(kicad_pcb
	(version 20260206)
	(generator "pcbnew")
	(generator_version "10.0")
	(general
		(thickness 1.6)
		(legacy_teardrops no)
	)
	(paper "A4")
	(layers
		(0 "F.Cu" signal "TOP")
		(4 "In1.Cu" signal "GND")
		(6 "In2.Cu" signal "IN1")
		(8 "In3.Cu" signal "GND1")
		(10 "In4.Cu" signal "IN2")
		(12 "In5.Cu" signal "GND2")
		(14 "In6.Cu" signal "IN3")
		(16 "In7.Cu" signal "GND3")
		(18 "In8.Cu" signal "VCC")
		(20 "In9.Cu" signal "VCC1")
		(22 "In10.Cu" signal "GND4")
		(24 "In11.Cu" signal "IN4")
		(26 "In12.Cu" signal "GND5")
		(28 "In13.Cu" signal "IN5")
		(30 "In14.Cu" signal "GND6")
		(32 "In15.Cu" signal "IN6")
		(34 "In16.Cu" signal "GND7")
		(2 "B.Cu" signal "BOTTOM")
		(9 "F.Adhes" user "F.Adhesive")
		(11 "B.Adhes" user "B.Adhesive")
		(13 "F.Paste" user "Package Geometry/Pastemask Top")
		(15 "B.Paste" user "Package Geometry/Pastemask Bottom")
		(5 "F.SilkS" user "Ref Des/Silkscreen Top")
		(7 "B.SilkS" user "Ref Des/Silkscreen Bottom")
		(1 "F.Mask" user "Board Geometry/Soldermask Top")
		(3 "B.Mask" user "Board Geometry/Soldermask Bottom")
		(17 "Dwgs.User" user "User.Drawings")
		(19 "Cmts.User" user "User.Comments")
		(21 "Eco1.User" user "User.Eco1")
		(23 "Eco2.User" user "User.Eco2")
		(25 "Edge.Cuts" user "Board Geometry/Outline")
		(27 "Margin" user)
		(31 "F.CrtYd" user "Package Geometry/Place Bound Top")
		(29 "B.CrtYd" user "Package Geometry/Place Bound Bottom")
		(35 "F.Fab" user "Ref Des/Assembly Top")
		(33 "B.Fab" user "Ref Des/Assembly Bottom")
	)
	(setup
		(pad_to_mask_clearance 0)
		(allow_soldermask_bridges_in_footprints no)
		(tenting
			(front yes)
			(back yes)
		)
		(covering
			(front no)
			(back no)
		)
		(plugging
			(front no)
			(back no)
		)
		(capping no)
		(filling no)
		(pcbplotparams
			(layerselection 0x00000000_00000000_55555555_5755f5ff)
			(plot_on_all_layers_selection 0x00000000_00000000_00000000_00000000)
			(disableapertmacros no)
			(usegerberextensions no)
			(usegerberattributes yes)
			(usegerberadvancedattributes yes)
			(creategerberjobfile yes)
			(dashed_line_dash_ratio 12)
			(dashed_line_gap_ratio 3)
			(svgprecision 4)
			(plotframeref no)
			(mode 1)
			(useauxorigin no)
			(pdf_front_fp_property_popups yes)
			(pdf_back_fp_property_popups yes)
			(pdf_metadata yes)
			(pdf_single_document no)
			(dxfpolygonmode yes)
			(dxfimperialunits yes)
			(dxfusepcbnewfont yes)
			(psnegative no)
			(psa4output no)
			(plot_black_and_white yes)
			(sketchpadsonfab no)
			(plotpadnumbers no)
			(hidednponfab no)
			(sketchdnponfab yes)
			(crossoutdnponfab yes)
			(subtractmaskfromsilk no)
			(outputformat 1)
			(mirror no)
			(drillshape 1)
			(scaleselection 1)
			(outputdirectory "")
		)
	)
	(arc
		(start 344.356436 -226.341686)
		(mid 344.073734 -226.26591)
		(end 343.791032 -226.341686)
		(width 0.088646)
		(layer "In11.Cu")
		(net "M_D_CPU0_SB_DQ<30>")
	)
	(arc
		(start 336.650584 -225.998786)
		(mid 336.570422 -225.726597)
		(end 336.368136 -225.527616)
		(width 0.088646)
		(layer "In11.Cu")
		(net "M_D_CPU0_SB_DQ<30>")
	)
	(arc
		(start 338.717382 -226.341686)
		(mid 338.440823 -226.265943)
		(end 338.162646 -226.33559)
		(width 0.088646)
		(layer "In11.Cu")
		(net "M_D_CPU0_SB_DQ<30>")
	)
	(arc
		(start 341.537036 -226.341686)
		(mid 341.262837 -226.265851)
		(end 340.986364 -226.33305)
		(width 0.088646)
		(layer "In11.Cu")
		(net "M_D_CPU0_SB_DQ<30>")
	)
	(arc
		(start 345.296236 -226.341686)
		(mid 345.022037 -226.265851)
		(end 344.745564 -226.33305)
		(width 0.088646)
		(layer "In11.Cu")
		(net "M_D_CPU0_SB_DQ<30>")
	)
	(arc
		(start 336.829146 -226.336606)
		(mid 336.698232 -226.200246)
		(end 336.650584 -226.017328)
		(width 0.088646)
		(layer "In11.Cu")
		(net "M_D_CPU0_SB_DQ<30>")
	)
	(arc
		(start 346.705682 -228.783388)
		(mid 346.570749 -228.650034)
		(end 346.518484 -228.467666)
		(width 0.088646)
		(layer "In11.Cu")
		(net "M_D_CPU0_SB_DQ<30>")
	)
	(arc
		(start 342.851232 -226.341686)
		(mid 342.664034 -226.391829)
		(end 342.476836 -226.341686)
		(width 0.088646)
		(layer "In11.Cu")
		(net "M_D_CPU0_SB_DQ<30>")
	)
	(arc
		(start 335.898236 -224.7138)
		(mid 335.615534 -224.638024)
		(end 335.332832 -224.7138)
		(width 0.088646)
		(layer "In11.Cu")
		(net "M_D_CPU0_SB_DQ<30>")
	)
	(arc
		(start 348.302834 -229.272846)
		(mid 347.960696 -229.029699)
		(end 347.557598 -228.912674)
		(width 0.088646)
		(layer "In11.Cu")
		(net "M_D_CPU0_SB_DQ<30>")
	)
	(arc
		(start 334.958436 -224.7138)
		(mid 334.675734 -224.638024)
		(end 334.393032 -224.7138)
		(width 0.088646)
		(layer "In11.Cu")
		(net "M_D_CPU0_SB_DQ<30>")
	)
	(arc
		(start 340.031832 -226.341686)
		(mid 339.844634 -226.391829)
		(end 339.657436 -226.341686)
		(width 0.088646)
		(layer "In11.Cu")
		(net "M_D_CPU0_SB_DQ<30>")
	)
	(arc
		(start 340.971632 -226.341686)
		(mid 340.784434 -226.391829)
		(end 340.597236 -226.341686)
		(width 0.088646)
		(layer "In11.Cu")
		(net "M_D_CPU0_SB_DQ<30>")
	)
	(arc
		(start 335.332832 -224.7138)
		(mid 335.145634 -224.763943)
		(end 334.958436 -224.7138)
		(width 0.088646)
		(layer "In11.Cu")
		(net "M_D_CPU0_SB_DQ<30>")
	)
	(arc
		(start 346.713302 -228.787706)
		(mid 346.709467 -228.785591)
		(end 346.705682 -228.783388)
		(width 0.088646)
		(layer "In11.Cu")
		(net "M_D_CPU0_SB_DQ<30>")
	)
	(arc
		(start 343.416636 -226.341686)
		(mid 343.142437 -226.265851)
		(end 342.865964 -226.33305)
		(width 0.088646)
		(layer "In11.Cu")
		(net "M_D_CPU0_SB_DQ<30>")
	)
	(arc
		(start 333.452978 -224.7138)
		(mid 333.26578 -224.763943)
		(end 333.078582 -224.7138)
		(width 0.088646)
		(layer "In11.Cu")
		(net "M_D_CPU0_SB_DQ<30>")
	)
	(arc
		(start 345.670632 -226.341686)
		(mid 345.483434 -226.391829)
		(end 345.296236 -226.341686)
		(width 0.088646)
		(layer "In11.Cu")
		(net "M_D_CPU0_SB_DQ<30>")
	)
	(arc
		(start 346.518484 -228.450394)
		(mid 346.570754 -228.268029)
		(end 346.705682 -228.134672)
		(width 0.088646)
		(layer "In11.Cu")
		(net "M_D_CPU0_SB_DQ<30>")
	)
	(arc
		(start 336.180684 -225.193352)
		(mid 336.102573 -224.916403)
		(end 335.898236 -224.7138)
		(width 0.088646)
		(layer "In11.Cu")
		(net "M_D_CPU0_SB_DQ<30>")
	)
	(arc
		(start 346.988384 -227.635054)
		(mid 346.910273 -227.358105)
		(end 346.705936 -227.155502)
		(width 0.088646)
		(layer "In11.Cu")
		(net "M_D_CPU0_SB_DQ<30>")
	)
	(arc
		(start 344.730832 -226.341686)
		(mid 344.543634 -226.391829)
		(end 344.356436 -226.341686)
		(width 0.088646)
		(layer "In11.Cu")
		(net "M_D_CPU0_SB_DQ<30>")
	)
	(arc
		(start 342.476836 -226.341686)
		(mid 342.202637 -226.265851)
		(end 341.926164 -226.33305)
		(width 0.088646)
		(layer "In11.Cu")
		(net "M_D_CPU0_SB_DQ<30>")
	)
	(arc
		(start 334.008222 -224.707704)
		(mid 333.72979 -224.637858)
		(end 333.452978 -224.7138)
		(width 0.088646)
		(layer "In11.Cu")
		(net "M_D_CPU0_SB_DQ<30>")
	)
	(arc
		(start 340.597236 -226.341686)
		(mid 340.323037 -226.265851)
		(end 340.046564 -226.33305)
		(width 0.088646)
		(layer "In11.Cu")
		(net "M_D_CPU0_SB_DQ<30>")
	)
	(arc
		(start 339.091778 -226.341686)
		(mid 338.90458 -226.391829)
		(end 338.717382 -226.341686)
		(width 0.088646)
		(layer "In11.Cu")
		(net "M_D_CPU0_SB_DQ<30>")
	)
	(arc
		(start 343.791032 -226.341686)
		(mid 343.603834 -226.391829)
		(end 343.416636 -226.341686)
		(width 0.088646)
		(layer "In11.Cu")
		(net "M_D_CPU0_SB_DQ<30>")
	)
	(arc
		(start 346.705682 -228.134672)
		(mid 346.909163 -227.933868)
		(end 346.988384 -227.659184)
		(width 0.088646)
		(layer "In11.Cu")
		(net "M_D_CPU0_SB_DQ<30>")
	)
	(arc
		(start 336.359246 -225.522536)
		(mid 336.228332 -225.386176)
		(end 336.180684 -225.203258)
		(width 0.088646)
		(layer "In11.Cu")
		(net "M_D_CPU0_SB_DQ<30>")
	)
	(arc
		(start 339.647022 -226.33559)
		(mid 339.36859 -226.265744)
		(end 339.091778 -226.341686)
		(width 0.088646)
		(layer "In11.Cu")
		(net "M_D_CPU0_SB_DQ<30>")
	)
	(arc
		(start 338.152232 -226.341686)
		(mid 337.965034 -226.391829)
		(end 337.777836 -226.341686)
		(width 0.088646)
		(layer "In11.Cu")
		(net "M_D_CPU0_SB_DQ<30>")
	)
	(arc
		(start 333.078582 -224.7138)
		(mid 332.94234 -224.657366)
		(end 332.796134 -224.638108)
		(width 0.088646)
		(layer "In11.Cu")
		(net "M_D_CPU0_SB_DQ<30>")
	)
	(arc
		(start 346.697046 -227.150422)
		(mid 346.566132 -227.014062)
		(end 346.518484 -226.831144)
		(width 0.088646)
		(layer "In11.Cu")
		(net "M_D_CPU0_SB_DQ<30>")
	)
	(arc
		(start 337.212432 -226.341686)
		(mid 337.025234 -226.391829)
		(end 336.838036 -226.341686)
		(width 0.088646)
		(layer "In11.Cu")
		(net "M_D_CPU0_SB_DQ<30>")
	)
	(segment
		(start 262.765286 -230.891842)
		(end 262.51027 -230.891842)
		(width 0.101854)
		(layer "F.Cu")
		(net "M_D_CPU0_SB_DQ<2>")
	)
	(segment
		(start 265.601958 -231.035606)
		(end 265.458194 -230.891842)
		(width 0.20066)
		(layer "F.Cu")
		(net "M_D_CPU0_SB_DQ<2>")
	)
	(segment
		(start 265.601958 -231.361234)
		(end 265.601958 -231.035606)
		(width 0.20066)
		(layer "F.Cu")
		(net "M_D_CPU0_SB_DQ<2>")
	)
	(segment
		(start 268.829282 -231.316784)
		(end 267.724382 -231.316784)
		(width 0.20066)
		(layer "F.Cu")
		(net "M_D_CPU0_SB_DQ<2>")
	)
	(segment
		(start 262.51027 -230.891842)
		(end 262.50011 -230.881682)
		(width 0.101854)
		(layer "F.Cu")
		(net "M_D_CPU0_SB_DQ<2>")
	)
	(segment
		(start 347.83268 -242.016788)
		(end 347.83268 -241.481102)
		(width 0.20066)
		(layer "F.Cu")
		(net "M_D_CPU0_SB_DQ<2>")
	)
	(segment
		(start 261.762748 -230.881682)
		(end 261.327646 -231.316784)
		(width 0.20066)
		(layer "F.Cu")
		(net "M_D_CPU0_SB_DQ<2>")
	)
	(segment
		(start 347.832934 -242.017042)
		(end 347.83268 -242.016788)
		(width 0.20066)
		(layer "F.Cu")
		(net "M_D_CPU0_SB_DQ<2>")
	)
	(segment
		(start 264.825226 -230.891842)
		(end 262.765286 -230.891842)
		(width 0.1016)
		(layer "F.Cu")
		(net "M_D_CPU0_SB_DQ<2>")
	)
	(segment
		(start 266.409678 -231.316784)
		(end 266.197842 -231.52862)
		(width 0.20066)
		(layer "F.Cu")
		(net "M_D_CPU0_SB_DQ<2>")
	)
	(segment
		(start 265.769344 -231.52862)
		(end 265.601958 -231.361234)
		(width 0.20066)
		(layer "F.Cu")
		(net "M_D_CPU0_SB_DQ<2>")
	)
	(segment
		(start 266.197842 -231.52862)
		(end 265.769344 -231.52862)
		(width 0.20066)
		(layer "F.Cu")
		(net "M_D_CPU0_SB_DQ<2>")
	)
	(segment
		(start 262.50011 -230.881682)
		(end 261.762748 -230.881682)
		(width 0.20066)
		(layer "F.Cu")
		(net "M_D_CPU0_SB_DQ<2>")
	)
	(segment
		(start 265.458194 -230.891842)
		(end 264.825226 -230.891842)
		(width 0.20066)
		(layer "F.Cu")
		(net "M_D_CPU0_SB_DQ<2>")
	)
	(segment
		(start 267.724382 -231.316784)
		(end 266.409678 -231.316784)
		(width 0.20066)
		(layer "F.Cu")
		(net "M_D_CPU0_SB_DQ<2>")
	)
	(segment
		(start 261.327646 -231.316784)
		(end 260.180582 -231.316784)
		(width 0.20066)
		(layer "F.Cu")
		(net "M_D_CPU0_SB_DQ<2>")
	)
	(segment
		(start 296.521632 -228.011736)
		(end 295.340786 -229.192582)
		(width 0.18288)
		(layer "In11.Cu")
		(net "M_D_CPU0_SB_DQ<2>")
	)
	(segment
		(start 314.54217 -231.780842)
		(end 314.453778 -231.744266)
		(width 0.18288)
		(layer "In11.Cu")
		(net "M_D_CPU0_SB_DQ<2>")
	)
	(segment
		(start 298.24807 -228.342444)
		(end 297.917362 -228.011736)
		(width 0.18288)
		(layer "In11.Cu")
		(net "M_D_CPU0_SB_DQ<2>")
	)
	(segment
		(start 285.71698 -227.995226)
		(end 284.700472 -227.995226)
		(width 0.18288)
		(layer "In11.Cu")
		(net "M_D_CPU0_SB_DQ<2>")
	)
	(segment
		(start 332.069186 -240.08588)
		(end 330.936092 -238.952786)
		(width 0.088646)
		(layer "In11.Cu")
		(net "M_D_CPU0_SB_DQ<2>")
	)
	(segment
		(start 330.313538 -238.952786)
		(end 321.706494 -238.952786)
		(width 0.18288)
		(layer "In11.Cu")
		(net "M_D_CPU0_SB_DQ<2>")
	)
	(segment
		(start 302.465994 -227.944426)
		(end 301.729394 -227.207826)
		(width 0.18288)
		(layer "In11.Cu")
		(net "M_D_CPU0_SB_DQ<2>")
	)
	(segment
		(start 342.006936 -241.80546)
		(end 341.996522 -241.799364)
		(width 0.088646)
		(layer "In11.Cu")
		(net "M_D_CPU0_SB_DQ<2>")
	)
	(segment
		(start 286.61106 -227.802186)
		(end 286.61106 -227.24491)
		(width 0.18288)
		(layer "In11.Cu")
		(net "M_D_CPU0_SB_DQ<2>")
	)
	(segment
		(start 305.831494 -229.417626)
		(end 304.358294 -227.944426)
		(width 0.18288)
		(layer "In11.Cu")
		(net "M_D_CPU0_SB_DQ<2>")
	)
	(segment
		(start 307.228494 -228.884226)
		(end 306.695094 -229.417626)
		(width 0.18288)
		(layer "In11.Cu")
		(net "M_D_CPU0_SB_DQ<2>")
	)
	(segment
		(start 335.240884 -241.481102)
		(end 335.240884 -241.471196)
		(width 0.088646)
		(layer "In11.Cu")
		(net "M_D_CPU0_SB_DQ<2>")
	)
	(segment
		(start 339.187282 -241.80546)
		(end 339.17255 -241.796824)
		(width 0.088646)
		(layer "In11.Cu")
		(net "M_D_CPU0_SB_DQ<2>")
	)
	(segment
		(start 270.834358 -231.452166)
		(end 270.834358 -231.726486)
		(width 0.18288)
		(layer "In11.Cu")
		(net "M_D_CPU0_SB_DQ<2>")
	)
	(segment
		(start 282.9814 -228.163374)
		(end 281.282394 -228.163374)
		(width 0.18288)
		(layer "In11.Cu")
		(net "M_D_CPU0_SB_DQ<2>")
	)
	(segment
		(start 340.127082 -241.80546)
		(end 340.11235 -241.796824)
		(width 0.088646)
		(layer "In11.Cu")
		(net "M_D_CPU0_SB_DQ<2>")
	)
	(segment
		(start 286.8041 -227.995226)
		(end 286.61106 -227.802186)
		(width 0.18288)
		(layer "In11.Cu")
		(net "M_D_CPU0_SB_DQ<2>")
	)
	(segment
		(start 313.588908 -231.744266)
		(end 312.887868 -231.043226)
		(width 0.18288)
		(layer "In11.Cu")
		(net "M_D_CPU0_SB_DQ<2>")
	)
	(segment
		(start 271.535398 -231.452166)
		(end 271.342358 -231.259126)
		(width 0.18288)
		(layer "In11.Cu")
		(net "M_D_CPU0_SB_DQ<2>")
	)
	(segment
		(start 271.535398 -231.726486)
		(end 271.535398 -231.452166)
		(width 0.18288)
		(layer "In11.Cu")
		(net "M_D_CPU0_SB_DQ<2>")
	)
	(segment
		(start 293.763446 -228.808026)
		(end 292.267894 -228.808026)
		(width 0.18288)
		(layer "In11.Cu")
		(net "M_D_CPU0_SB_DQ<2>")
	)
	(segment
		(start 273.995642 -230.90251)
		(end 272.978626 -231.919526)
		(width 0.18288)
		(layer "In11.Cu")
		(net "M_D_CPU0_SB_DQ<2>")
	)
	(segment
		(start 286.61106 -227.24491)
		(end 286.41802 -227.05187)
		(width 0.18288)
		(layer "In11.Cu")
		(net "M_D_CPU0_SB_DQ<2>")
	)
	(segment
		(start 333.548482 -240.177574)
		(end 333.53375 -240.168938)
		(width 0.088646)
		(layer "In11.Cu")
		(net "M_D_CPU0_SB_DQ<2>")
	)
	(segment
		(start 286.10306 -227.05187)
		(end 285.91002 -227.24491)
		(width 0.18288)
		(layer "In11.Cu")
		(net "M_D_CPU0_SB_DQ<2>")
	)
	(segment
		(start 309.677308 -230.893112)
		(end 307.668422 -228.884226)
		(width 0.18288)
		(layer "In11.Cu")
		(net "M_D_CPU0_SB_DQ<2>")
	)
	(segment
		(start 310.820054 -231.043226)
		(end 310.66994 -230.893112)
		(width 0.18288)
		(layer "In11.Cu")
		(net "M_D_CPU0_SB_DQ<2>")
	)
	(segment
		(start 280.253186 -229.192582)
		(end 279.11425 -229.192582)
		(width 0.18288)
		(layer "In11.Cu")
		(net "M_D_CPU0_SB_DQ<2>")
	)
	(segment
		(start 272.978626 -231.919526)
		(end 271.728438 -231.919526)
		(width 0.18288)
		(layer "In11.Cu")
		(net "M_D_CPU0_SB_DQ<2>")
	)
	(segment
		(start 270.641318 -231.919526)
		(end 270.0274 -231.919526)
		(width 0.18288)
		(layer "In11.Cu")
		(net "M_D_CPU0_SB_DQ<2>")
	)
	(segment
		(start 274.52701 -230.90251)
		(end 273.995642 -230.90251)
		(width 0.18288)
		(layer "In11.Cu")
		(net "M_D_CPU0_SB_DQ<2>")
	)
	(segment
		(start 334.018636 -240.991644)
		(end 334.009746 -240.986564)
		(width 0.088646)
		(layer "In11.Cu")
		(net "M_D_CPU0_SB_DQ<2>")
	)
	(segment
		(start 314.453778 -231.744266)
		(end 313.588908 -231.744266)
		(width 0.18288)
		(layer "In11.Cu")
		(net "M_D_CPU0_SB_DQ<2>")
	)
	(segment
		(start 291.759894 -229.316026)
		(end 290.591494 -229.316026)
		(width 0.18288)
		(layer "In11.Cu")
		(net "M_D_CPU0_SB_DQ<2>")
	)
	(segment
		(start 276.621494 -229.951026)
		(end 275.478494 -229.951026)
		(width 0.18288)
		(layer "In11.Cu")
		(net "M_D_CPU0_SB_DQ<2>")
	)
	(segment
		(start 338.247482 -241.80546)
		(end 338.23275 -241.796824)
		(width 0.088646)
		(layer "In11.Cu")
		(net "M_D_CPU0_SB_DQ<2>")
	)
	(segment
		(start 278.856694 -228.935026)
		(end 277.637494 -228.935026)
		(width 0.18288)
		(layer "In11.Cu")
		(net "M_D_CPU0_SB_DQ<2>")
	)
	(segment
		(start 312.887868 -231.043226)
		(end 310.820054 -231.043226)
		(width 0.18288)
		(layer "In11.Cu")
		(net "M_D_CPU0_SB_DQ<2>")
	)
	(segment
		(start 336.376518 -241.810286)
		(end 336.368136 -241.80546)
		(width 0.088646)
		(layer "In11.Cu")
		(net "M_D_CPU0_SB_DQ<2>")
	)
	(segment
		(start 310.66994 -230.893112)
		(end 309.677308 -230.893112)
		(width 0.18288)
		(layer "In11.Cu")
		(net "M_D_CPU0_SB_DQ<2>")
	)
	(segment
		(start 270.0274 -231.919526)
		(end 269.424658 -231.316784)
		(width 0.18288)
		(layer "In11.Cu")
		(net "M_D_CPU0_SB_DQ<2>")
	)
	(segment
		(start 335.428336 -241.80546)
		(end 335.419446 -241.80038)
		(width 0.088646)
		(layer "In11.Cu")
		(net "M_D_CPU0_SB_DQ<2>")
	)
	(segment
		(start 304.358294 -227.944426)
		(end 302.465994 -227.944426)
		(width 0.18288)
		(layer "In11.Cu")
		(net "M_D_CPU0_SB_DQ<2>")
	)
	(segment
		(start 289.270694 -227.995226)
		(end 286.8041 -227.995226)
		(width 0.18288)
		(layer "In11.Cu")
		(net "M_D_CPU0_SB_DQ<2>")
	)
	(segment
		(start 290.591494 -229.316026)
		(end 289.270694 -227.995226)
		(width 0.18288)
		(layer "In11.Cu")
		(net "M_D_CPU0_SB_DQ<2>")
	)
	(segment
		(start 306.695094 -229.417626)
		(end 305.831494 -229.417626)
		(width 0.18288)
		(layer "In11.Cu")
		(net "M_D_CPU0_SB_DQ<2>")
	)
	(segment
		(start 269.424658 -231.316784)
		(end 268.829282 -231.316784)
		(width 0.18288)
		(layer "In11.Cu")
		(net "M_D_CPU0_SB_DQ<2>")
	)
	(segment
		(start 301.729394 -227.207826)
		(end 301.033688 -227.207826)
		(width 0.18288)
		(layer "In11.Cu")
		(net "M_D_CPU0_SB_DQ<2>")
	)
	(segment
		(start 286.41802 -227.05187)
		(end 286.10306 -227.05187)
		(width 0.18288)
		(layer "In11.Cu")
		(net "M_D_CPU0_SB_DQ<2>")
	)
	(segment
		(start 292.267894 -228.808026)
		(end 291.759894 -229.316026)
		(width 0.18288)
		(layer "In11.Cu")
		(net "M_D_CPU0_SB_DQ<2>")
	)
	(segment
		(start 271.728438 -231.919526)
		(end 271.535398 -231.726486)
		(width 0.18288)
		(layer "In11.Cu")
		(net "M_D_CPU0_SB_DQ<2>")
	)
	(segment
		(start 333.831184 -240.667286)
		(end 333.831184 -240.653062)
		(width 0.088646)
		(layer "In11.Cu")
		(net "M_D_CPU0_SB_DQ<2>")
	)
	(segment
		(start 279.11425 -229.192582)
		(end 278.856694 -228.935026)
		(width 0.18288)
		(layer "In11.Cu")
		(net "M_D_CPU0_SB_DQ<2>")
	)
	(segment
		(start 297.917362 -228.011736)
		(end 296.521632 -228.011736)
		(width 0.18288)
		(layer "In11.Cu")
		(net "M_D_CPU0_SB_DQ<2>")
	)
	(segment
		(start 275.478494 -229.951026)
		(end 274.52701 -230.90251)
		(width 0.18288)
		(layer "In11.Cu")
		(net "M_D_CPU0_SB_DQ<2>")
	)
	(segment
		(start 281.282394 -228.163374)
		(end 280.253186 -229.192582)
		(width 0.18288)
		(layer "In11.Cu")
		(net "M_D_CPU0_SB_DQ<2>")
	)
	(segment
		(start 337.307682 -241.80546)
		(end 337.29295 -241.796824)
		(width 0.088646)
		(layer "In11.Cu")
		(net "M_D_CPU0_SB_DQ<2>")
	)
	(segment
		(start 307.668422 -228.884226)
		(end 307.228494 -228.884226)
		(width 0.18288)
		(layer "In11.Cu")
		(net "M_D_CPU0_SB_DQ<2>")
	)
	(segment
		(start 277.637494 -228.935026)
		(end 276.621494 -229.951026)
		(width 0.18288)
		(layer "In11.Cu")
		(net "M_D_CPU0_SB_DQ<2>")
	)
	(segment
		(start 330.936092 -238.952786)
		(end 330.313538 -238.952786)
		(width 0.088646)
		(layer "In11.Cu")
		(net "M_D_CPU0_SB_DQ<2>")
	)
	(segment
		(start 345.765882 -241.80546)
		(end 345.75115 -241.796824)
		(width 0.088646)
		(layer "In11.Cu")
		(net "M_D_CPU0_SB_DQ<2>")
	)
	(segment
		(start 332.26629 -240.08588)
		(end 332.069186 -240.08588)
		(width 0.088646)
		(layer "In11.Cu")
		(net "M_D_CPU0_SB_DQ<2>")
	)
	(segment
		(start 321.706494 -238.952786)
		(end 314.54217 -231.780842)
		(width 0.18288)
		(layer "In11.Cu")
		(net "M_D_CPU0_SB_DQ<2>")
	)
	(segment
		(start 341.066882 -241.80546)
		(end 341.05215 -241.796824)
		(width 0.088646)
		(layer "In11.Cu")
		(net "M_D_CPU0_SB_DQ<2>")
	)
	(segment
		(start 295.340786 -229.192582)
		(end 294.148002 -229.192582)
		(width 0.18288)
		(layer "In11.Cu")
		(net "M_D_CPU0_SB_DQ<2>")
	)
	(segment
		(start 301.033688 -227.207826)
		(end 299.89907 -228.342444)
		(width 0.18288)
		(layer "In11.Cu")
		(net "M_D_CPU0_SB_DQ<2>")
	)
	(segment
		(start 284.700472 -227.995226)
		(end 284.353254 -228.342444)
		(width 0.18288)
		(layer "In11.Cu")
		(net "M_D_CPU0_SB_DQ<2>")
	)
	(segment
		(start 336.368136 -241.80546)
		(end 336.353404 -241.796824)
		(width 0.088646)
		(layer "In11.Cu")
		(net "M_D_CPU0_SB_DQ<2>")
	)
	(segment
		(start 294.148002 -229.192582)
		(end 293.763446 -228.808026)
		(width 0.18288)
		(layer "In11.Cu")
		(net "M_D_CPU0_SB_DQ<2>")
	)
	(segment
		(start 347.83268 -241.481102)
		(end 347.541596 -241.481102)
		(width 0.088646)
		(layer "In11.Cu")
		(net "M_D_CPU0_SB_DQ<2>")
	)
	(segment
		(start 285.91002 -227.24491)
		(end 285.91002 -227.802186)
		(width 0.18288)
		(layer "In11.Cu")
		(net "M_D_CPU0_SB_DQ<2>")
	)
	(segment
		(start 344.826082 -241.80546)
		(end 344.81135 -241.796824)
		(width 0.088646)
		(layer "In11.Cu")
		(net "M_D_CPU0_SB_DQ<2>")
	)
	(segment
		(start 343.886282 -241.80546)
		(end 343.87155 -241.796824)
		(width 0.088646)
		(layer "In11.Cu")
		(net "M_D_CPU0_SB_DQ<2>")
	)
	(segment
		(start 346.362274 -241.677444)
		(end 346.140278 -241.80546)
		(width 0.088646)
		(layer "In11.Cu")
		(net "M_D_CPU0_SB_DQ<2>")
	)
	(segment
		(start 284.353254 -228.342444)
		(end 283.16047 -228.342444)
		(width 0.18288)
		(layer "In11.Cu")
		(net "M_D_CPU0_SB_DQ<2>")
	)
	(segment
		(start 283.16047 -228.342444)
		(end 282.9814 -228.163374)
		(width 0.18288)
		(layer "In11.Cu")
		(net "M_D_CPU0_SB_DQ<2>")
	)
	(segment
		(start 270.834358 -231.726486)
		(end 270.641318 -231.919526)
		(width 0.18288)
		(layer "In11.Cu")
		(net "M_D_CPU0_SB_DQ<2>")
	)
	(segment
		(start 285.91002 -227.802186)
		(end 285.71698 -227.995226)
		(width 0.18288)
		(layer "In11.Cu")
		(net "M_D_CPU0_SB_DQ<2>")
	)
	(segment
		(start 342.946482 -241.80546)
		(end 342.936068 -241.799364)
		(width 0.088646)
		(layer "In11.Cu")
		(net "M_D_CPU0_SB_DQ<2>")
	)
	(segment
		(start 299.89907 -228.342444)
		(end 298.24807 -228.342444)
		(width 0.18288)
		(layer "In11.Cu")
		(net "M_D_CPU0_SB_DQ<2>")
	)
	(segment
		(start 271.027398 -231.259126)
		(end 270.834358 -231.452166)
		(width 0.18288)
		(layer "In11.Cu")
		(net "M_D_CPU0_SB_DQ<2>")
	)
	(segment
		(start 271.342358 -231.259126)
		(end 271.027398 -231.259126)
		(width 0.18288)
		(layer "In11.Cu")
		(net "M_D_CPU0_SB_DQ<2>")
	)
	(arc
		(start 342.936068 -241.799364)
		(mid 342.65789 -241.729641)
		(end 342.381332 -241.80546)
		(width 0.088646)
		(layer "In11.Cu")
		(net "M_D_CPU0_SB_DQ<2>")
	)
	(arc
		(start 346.140278 -241.80546)
		(mid 345.95308 -241.855603)
		(end 345.765882 -241.80546)
		(width 0.088646)
		(layer "In11.Cu")
		(net "M_D_CPU0_SB_DQ<2>")
	)
	(arc
		(start 337.29295 -241.796824)
		(mid 337.016475 -241.729504)
		(end 336.742278 -241.80546)
		(width 0.088646)
		(layer "In11.Cu")
		(net "M_D_CPU0_SB_DQ<2>")
	)
	(arc
		(start 334.393032 -240.991644)
		(mid 334.205834 -241.041787)
		(end 334.018636 -240.991644)
		(width 0.088646)
		(layer "In11.Cu")
		(net "M_D_CPU0_SB_DQ<2>")
	)
	(arc
		(start 333.53375 -240.168938)
		(mid 333.257309 -240.101772)
		(end 332.983078 -240.177574)
		(width 0.088646)
		(layer "In11.Cu")
		(net "M_D_CPU0_SB_DQ<2>")
	)
	(arc
		(start 341.996522 -241.799364)
		(mid 341.71809 -241.729518)
		(end 341.441278 -241.80546)
		(width 0.088646)
		(layer "In11.Cu")
		(net "M_D_CPU0_SB_DQ<2>")
	)
	(arc
		(start 333.831184 -240.653062)
		(mid 333.751965 -240.378377)
		(end 333.548482 -240.177574)
		(width 0.088646)
		(layer "In11.Cu")
		(net "M_D_CPU0_SB_DQ<2>")
	)
	(arc
		(start 340.501478 -241.80546)
		(mid 340.31428 -241.855603)
		(end 340.127082 -241.80546)
		(width 0.088646)
		(layer "In11.Cu")
		(net "M_D_CPU0_SB_DQ<2>")
	)
	(arc
		(start 332.608682 -240.177574)
		(mid 332.443524 -240.109169)
		(end 332.26629 -240.08588)
		(width 0.088646)
		(layer "In11.Cu")
		(net "M_D_CPU0_SB_DQ<2>")
	)
	(arc
		(start 346.441268 -241.616738)
		(mid 346.403764 -241.649685)
		(end 346.362274 -241.677444)
		(width 0.088646)
		(layer "In11.Cu")
		(net "M_D_CPU0_SB_DQ<2>")
	)
	(arc
		(start 336.742278 -241.80546)
		(mid 336.560027 -241.855571)
		(end 336.376518 -241.810286)
		(width 0.088646)
		(layer "In11.Cu")
		(net "M_D_CPU0_SB_DQ<2>")
	)
	(arc
		(start 340.11235 -241.796824)
		(mid 339.835875 -241.729504)
		(end 339.561678 -241.80546)
		(width 0.088646)
		(layer "In11.Cu")
		(net "M_D_CPU0_SB_DQ<2>")
	)
	(arc
		(start 332.983078 -240.177574)
		(mid 332.79588 -240.227717)
		(end 332.608682 -240.177574)
		(width 0.088646)
		(layer "In11.Cu")
		(net "M_D_CPU0_SB_DQ<2>")
	)
	(arc
		(start 339.561678 -241.80546)
		(mid 339.37448 -241.855603)
		(end 339.187282 -241.80546)
		(width 0.088646)
		(layer "In11.Cu")
		(net "M_D_CPU0_SB_DQ<2>")
	)
	(arc
		(start 334.009746 -240.986564)
		(mid 333.878832 -240.850204)
		(end 333.831184 -240.667286)
		(width 0.088646)
		(layer "In11.Cu")
		(net "M_D_CPU0_SB_DQ<2>")
	)
	(arc
		(start 345.75115 -241.796824)
		(mid 345.474675 -241.729504)
		(end 345.200478 -241.80546)
		(width 0.088646)
		(layer "In11.Cu")
		(net "M_D_CPU0_SB_DQ<2>")
	)
	(arc
		(start 338.23275 -241.796824)
		(mid 337.956275 -241.729504)
		(end 337.682078 -241.80546)
		(width 0.088646)
		(layer "In11.Cu")
		(net "M_D_CPU0_SB_DQ<2>")
	)
	(arc
		(start 341.441278 -241.80546)
		(mid 341.25408 -241.855603)
		(end 341.066882 -241.80546)
		(width 0.088646)
		(layer "In11.Cu")
		(net "M_D_CPU0_SB_DQ<2>")
	)
	(arc
		(start 335.240884 -241.471196)
		(mid 335.162773 -241.194247)
		(end 334.958436 -240.991644)
		(width 0.088646)
		(layer "In11.Cu")
		(net "M_D_CPU0_SB_DQ<2>")
	)
	(arc
		(start 342.381332 -241.80546)
		(mid 342.194134 -241.855603)
		(end 342.006936 -241.80546)
		(width 0.088646)
		(layer "In11.Cu")
		(net "M_D_CPU0_SB_DQ<2>")
	)
	(arc
		(start 337.682078 -241.80546)
		(mid 337.49488 -241.855603)
		(end 337.307682 -241.80546)
		(width 0.088646)
		(layer "In11.Cu")
		(net "M_D_CPU0_SB_DQ<2>")
	)
	(arc
		(start 335.802732 -241.80546)
		(mid 335.615534 -241.855603)
		(end 335.428336 -241.80546)
		(width 0.088646)
		(layer "In11.Cu")
		(net "M_D_CPU0_SB_DQ<2>")
	)
	(arc
		(start 343.87155 -241.796824)
		(mid 343.595075 -241.729504)
		(end 343.320878 -241.80546)
		(width 0.088646)
		(layer "In11.Cu")
		(net "M_D_CPU0_SB_DQ<2>")
	)
	(arc
		(start 344.81135 -241.796824)
		(mid 344.534875 -241.729504)
		(end 344.260678 -241.80546)
		(width 0.088646)
		(layer "In11.Cu")
		(net "M_D_CPU0_SB_DQ<2>")
	)
	(arc
		(start 339.17255 -241.796824)
		(mid 338.896075 -241.729504)
		(end 338.621878 -241.80546)
		(width 0.088646)
		(layer "In11.Cu")
		(net "M_D_CPU0_SB_DQ<2>")
	)
	(arc
		(start 345.200478 -241.80546)
		(mid 345.01328 -241.855603)
		(end 344.826082 -241.80546)
		(width 0.088646)
		(layer "In11.Cu")
		(net "M_D_CPU0_SB_DQ<2>")
	)
	(arc
		(start 343.320878 -241.80546)
		(mid 343.13368 -241.855603)
		(end 342.946482 -241.80546)
		(width 0.088646)
		(layer "In11.Cu")
		(net "M_D_CPU0_SB_DQ<2>")
	)
	(arc
		(start 334.958436 -240.991644)
		(mid 334.675734 -240.915868)
		(end 334.393032 -240.991644)
		(width 0.088646)
		(layer "In11.Cu")
		(net "M_D_CPU0_SB_DQ<2>")
	)
	(arc
		(start 347.217238 -241.29365)
		(mid 346.801143 -241.117756)
		(end 346.518484 -241.47018)
		(width 0.088646)
		(layer "In11.Cu")
		(net "M_D_CPU0_SB_DQ<2>")
	)
	(arc
		(start 336.353404 -241.796824)
		(mid 336.076929 -241.729504)
		(end 335.802732 -241.80546)
		(width 0.088646)
		(layer "In11.Cu")
		(net "M_D_CPU0_SB_DQ<2>")
	)
	(arc
		(start 338.621878 -241.80546)
		(mid 338.43468 -241.855603)
		(end 338.247482 -241.80546)
		(width 0.088646)
		(layer "In11.Cu")
		(net "M_D_CPU0_SB_DQ<2>")
	)
	(arc
		(start 347.541596 -241.481102)
		(mid 347.354276 -241.430872)
		(end 347.217238 -241.29365)
		(width 0.088646)
		(layer "In11.Cu")
		(net "M_D_CPU0_SB_DQ<2>")
	)
	(arc
		(start 341.05215 -241.796824)
		(mid 340.775675 -241.729504)
		(end 340.501478 -241.80546)
		(width 0.088646)
		(layer "In11.Cu")
		(net "M_D_CPU0_SB_DQ<2>")
	)
	(arc
		(start 346.518484 -241.47018)
		(mid 346.496938 -241.552441)
		(end 346.441268 -241.616738)
		(width 0.088646)
		(layer "In11.Cu")
		(net "M_D_CPU0_SB_DQ<2>")
	)
	(arc
		(start 335.419446 -241.80038)
		(mid 335.288532 -241.66402)
		(end 335.240884 -241.481102)
		(width 0.088646)
		(layer "In11.Cu")
		(net "M_D_CPU0_SB_DQ<2>")
	)
	(arc
		(start 344.260678 -241.80546)
		(mid 344.07348 -241.855603)
		(end 343.886282 -241.80546)
		(width 0.088646)
		(layer "In11.Cu")
		(net "M_D_CPU0_SB_DQ<2>")
	)
	(segment
		(start 261.050786 -196.041772)
		(end 259.065268 -196.041772)
		(width 0.1016)
		(layer "F.Cu")
		(net "M_D_CPU0_SB_DQ<29>")
	)
	(segment
		(start 258.44754 -196.032882)
		(end 258.28498 -196.195442)
		(width 0.20066)
		(layer "F.Cu")
		(net "M_D_CPU0_SB_DQ<29>")
	)
	(segment
		(start 257.626104 -196.678042)
		(end 257.414776 -196.466714)
		(width 0.20066)
		(layer "F.Cu")
		(net "M_D_CPU0_SB_DQ<29>")
	)
	(segment
		(start 258.130548 -196.678042)
		(end 257.626104 -196.678042)
		(width 0.20066)
		(layer "F.Cu")
		(net "M_D_CPU0_SB_DQ<29>")
	)
	(segment
		(start 261.984998 -196.466714)
		(end 261.560056 -196.041772)
		(width 0.20066)
		(layer "F.Cu")
		(net "M_D_CPU0_SB_DQ<29>")
	)
	(segment
		(start 264.729214 -196.466714)
		(end 263.624314 -196.466714)
		(width 0.20066)
		(layer "F.Cu")
		(net "M_D_CPU0_SB_DQ<29>")
	)
	(segment
		(start 261.381494 -196.041772)
		(end 261.050786 -196.041772)
		(width 0.101854)
		(layer "F.Cu")
		(net "M_D_CPU0_SB_DQ<29>")
	)
	(segment
		(start 263.624314 -196.466714)
		(end 261.984998 -196.466714)
		(width 0.20066)
		(layer "F.Cu")
		(net "M_D_CPU0_SB_DQ<29>")
	)
	(segment
		(start 258.28498 -196.52361)
		(end 258.130548 -196.678042)
		(width 0.20066)
		(layer "F.Cu")
		(net "M_D_CPU0_SB_DQ<29>")
	)
	(segment
		(start 346.89288 -228.994716)
		(end 346.89288 -228.45903)
		(width 0.20066)
		(layer "F.Cu")
		(net "M_D_CPU0_SB_DQ<29>")
	)
	(segment
		(start 259.065268 -196.041772)
		(end 259.056378 -196.032882)
		(width 0.1016)
		(layer "F.Cu")
		(net "M_D_CPU0_SB_DQ<29>")
	)
	(segment
		(start 258.28498 -196.195442)
		(end 258.28498 -196.52361)
		(width 0.20066)
		(layer "F.Cu")
		(net "M_D_CPU0_SB_DQ<29>")
	)
	(segment
		(start 346.893134 -228.99497)
		(end 346.89288 -228.994716)
		(width 0.20066)
		(layer "F.Cu")
		(net "M_D_CPU0_SB_DQ<29>")
	)
	(segment
		(start 257.414776 -196.466714)
		(end 256.080514 -196.466714)
		(width 0.20066)
		(layer "F.Cu")
		(net "M_D_CPU0_SB_DQ<29>")
	)
	(segment
		(start 261.560056 -196.041772)
		(end 261.381494 -196.041772)
		(width 0.20066)
		(layer "F.Cu")
		(net "M_D_CPU0_SB_DQ<29>")
	)
	(segment
		(start 259.056378 -196.032882)
		(end 258.44754 -196.032882)
		(width 0.20066)
		(layer "F.Cu")
		(net "M_D_CPU0_SB_DQ<29>")
	)
	(segment
		(start 338.162646 -225.699066)
		(end 338.152232 -225.69297)
		(width 0.088646)
		(layer "In11.Cu")
		(net "M_D_CPU0_SB_DQ<29>")
	)
	(segment
		(start 345.685364 -225.701606)
		(end 345.670632 -225.69297)
		(width 0.088646)
		(layer "In11.Cu")
		(net "M_D_CPU0_SB_DQ<29>")
	)
	(segment
		(start 267.909294 -196.04228)
		(end 267.716762 -195.962524)
		(width 0.18288)
		(layer "In11.Cu")
		(net "M_D_CPU0_SB_DQ<29>")
	)
	(segment
		(start 332.286102 -223.917256)
		(end 332.286102 -223.917002)
		(width 0.088646)
		(layer "In11.Cu")
		(net "M_D_CPU0_SB_DQ<29>")
	)
	(segment
		(start 332.286102 -223.917002)
		(end 331.608938 -223.239838)
		(width 0.088646)
		(layer "In11.Cu")
		(net "M_D_CPU0_SB_DQ<29>")
	)
	(segment
		(start 265.973052 -195.962524)
		(end 264.729214 -196.466714)
		(width 0.18288)
		(layer "In11.Cu")
		(net "M_D_CPU0_SB_DQ<29>")
	)
	(segment
		(start 336.92973 -225.217482)
		(end 336.92973 -225.194622)
		(width 0.088646)
		(layer "In11.Cu")
		(net "M_D_CPU0_SB_DQ<29>")
	)
	(segment
		(start 271.089374 -195.7578)
		(end 270.259302 -196.101716)
		(width 0.18288)
		(layer "In11.Cu")
		(net "M_D_CPU0_SB_DQ<29>")
	)
	(segment
		(start 334.018636 -224.065084)
		(end 334.008222 -224.07118)
		(width 0.088646)
		(layer "In11.Cu")
		(net "M_D_CPU0_SB_DQ<29>")
	)
	(segment
		(start 331.608938 -221.653608)
		(end 330.82103 -220.8657)
		(width 0.088646)
		(layer "In11.Cu")
		(net "M_D_CPU0_SB_DQ<29>")
	)
	(segment
		(start 339.102192 -225.699066)
		(end 339.091778 -225.69297)
		(width 0.088646)
		(layer "In11.Cu")
		(net "M_D_CPU0_SB_DQ<29>")
	)
	(segment
		(start 332.796388 -224.140776)
		(end 332.509622 -224.140776)
		(width 0.088646)
		(layer "In11.Cu")
		(net "M_D_CPU0_SB_DQ<29>")
	)
	(segment
		(start 340.986364 -225.701606)
		(end 340.971632 -225.69297)
		(width 0.088646)
		(layer "In11.Cu")
		(net "M_D_CPU0_SB_DQ<29>")
	)
	(segment
		(start 274.140422 -194.292982)
		(end 271.676368 -195.170806)
		(width 0.18288)
		(layer "In11.Cu")
		(net "M_D_CPU0_SB_DQ<29>")
	)
	(segment
		(start 343.805764 -225.701606)
		(end 343.791032 -225.69297)
		(width 0.088646)
		(layer "In11.Cu")
		(net "M_D_CPU0_SB_DQ<29>")
	)
	(segment
		(start 346.619322 -225.69805)
		(end 346.610432 -225.69297)
		(width 0.088646)
		(layer "In11.Cu")
		(net "M_D_CPU0_SB_DQ<29>")
	)
	(segment
		(start 313.318652 -194.988942)
		(end 312.041286 -194.292982)
		(width 0.18288)
		(layer "In11.Cu")
		(net "M_D_CPU0_SB_DQ<29>")
	)
	(segment
		(start 270.259302 -196.101716)
		(end 269.56766 -196.101716)
		(width 0.18288)
		(layer "In11.Cu")
		(net "M_D_CPU0_SB_DQ<29>")
	)
	(segment
		(start 346.797884 -226.027234)
		(end 346.797884 -226.017328)
		(width 0.088646)
		(layer "In11.Cu")
		(net "M_D_CPU0_SB_DQ<29>")
	)
	(segment
		(start 318.657732 -204.473302)
		(end 314.754006 -196.424296)
		(width 0.18288)
		(layer "In11.Cu")
		(net "M_D_CPU0_SB_DQ<29>")
	)
	(segment
		(start 346.89288 -228.45903)
		(end 347.205808 -228.45903)
		(width 0.088646)
		(layer "In11.Cu")
		(net "M_D_CPU0_SB_DQ<29>")
	)
	(segment
		(start 269.56766 -196.101716)
		(end 269.42415 -196.04228)
		(width 0.18288)
		(layer "In11.Cu")
		(net "M_D_CPU0_SB_DQ<29>")
	)
	(segment
		(start 271.676368 -195.170806)
		(end 271.089374 -195.7578)
		(width 0.18288)
		(layer "In11.Cu")
		(net "M_D_CPU0_SB_DQ<29>")
	)
	(segment
		(start 342.865964 -225.701606)
		(end 342.851232 -225.69297)
		(width 0.088646)
		(layer "In11.Cu")
		(net "M_D_CPU0_SB_DQ<29>")
	)
	(segment
		(start 341.926164 -225.701606)
		(end 341.911432 -225.69297)
		(width 0.088646)
		(layer "In11.Cu")
		(net "M_D_CPU0_SB_DQ<29>")
	)
	(segment
		(start 325.694294 -211.509864)
		(end 318.657732 -204.473302)
		(width 0.18288)
		(layer "In11.Cu")
		(net "M_D_CPU0_SB_DQ<29>")
	)
	(segment
		(start 332.509622 -224.140776)
		(end 332.286102 -223.917256)
		(width 0.088646)
		(layer "In11.Cu")
		(net "M_D_CPU0_SB_DQ<29>")
	)
	(segment
		(start 340.046564 -225.701606)
		(end 340.031832 -225.69297)
		(width 0.088646)
		(layer "In11.Cu")
		(net "M_D_CPU0_SB_DQ<29>")
	)
	(segment
		(start 347.549978 -227.969318)
		(end 347.558868 -227.964238)
		(width 0.088646)
		(layer "In11.Cu")
		(net "M_D_CPU0_SB_DQ<29>")
	)
	(segment
		(start 330.82103 -220.8657)
		(end 325.694294 -215.738964)
		(width 0.18288)
		(layer "In11.Cu")
		(net "M_D_CPU0_SB_DQ<29>")
	)
	(segment
		(start 336.460084 -224.399348)
		(end 336.460084 -224.389442)
		(width 0.088646)
		(layer "In11.Cu")
		(net "M_D_CPU0_SB_DQ<29>")
	)
	(segment
		(start 314.754006 -196.424296)
		(end 313.318652 -194.988942)
		(width 0.18288)
		(layer "In11.Cu")
		(net "M_D_CPU0_SB_DQ<29>")
	)
	(segment
		(start 325.694294 -215.738964)
		(end 325.694294 -211.509864)
		(width 0.18288)
		(layer "In11.Cu")
		(net "M_D_CPU0_SB_DQ<29>")
	)
	(segment
		(start 331.608938 -223.239838)
		(end 331.608938 -221.653608)
		(width 0.088646)
		(layer "In11.Cu")
		(net "M_D_CPU0_SB_DQ<29>")
	)
	(segment
		(start 347.205808 -228.45903)
		(end 347.270832 -228.394006)
		(width 0.088646)
		(layer "In11.Cu")
		(net "M_D_CPU0_SB_DQ<29>")
	)
	(segment
		(start 336.281522 -224.070164)
		(end 336.272632 -224.065084)
		(width 0.088646)
		(layer "In11.Cu")
		(net "M_D_CPU0_SB_DQ<29>")
	)
	(segment
		(start 269.42415 -196.04228)
		(end 267.909294 -196.04228)
		(width 0.18288)
		(layer "In11.Cu")
		(net "M_D_CPU0_SB_DQ<29>")
	)
	(segment
		(start 347.558868 -227.325682)
		(end 347.549978 -227.320602)
		(width 0.088646)
		(layer "In11.Cu")
		(net "M_D_CPU0_SB_DQ<29>")
	)
	(segment
		(start 347.089222 -226.511866)
		(end 347.080332 -226.506786)
		(width 0.088646)
		(layer "In11.Cu")
		(net "M_D_CPU0_SB_DQ<29>")
	)
	(segment
		(start 267.716762 -195.962524)
		(end 265.973052 -195.962524)
		(width 0.18288)
		(layer "In11.Cu")
		(net "M_D_CPU0_SB_DQ<29>")
	)
	(segment
		(start 312.041286 -194.292982)
		(end 274.140422 -194.292982)
		(width 0.18288)
		(layer "In11.Cu")
		(net "M_D_CPU0_SB_DQ<29>")
	)
	(segment
		(start 347.267784 -226.846638)
		(end 347.267784 -226.831144)
		(width 0.088646)
		(layer "In11.Cu")
		(net "M_D_CPU0_SB_DQ<29>")
	)
	(segment
		(start 344.745564 -225.701606)
		(end 344.730832 -225.69297)
		(width 0.088646)
		(layer "In11.Cu")
		(net "M_D_CPU0_SB_DQ<29>")
	)
	(segment
		(start 337.227164 -225.701606)
		(end 337.212432 -225.69297)
		(width 0.088646)
		(layer "In11.Cu")
		(net "M_D_CPU0_SB_DQ<29>")
	)
	(arc
		(start 344.356436 -225.69297)
		(mid 344.082207 -225.768895)
		(end 343.805764 -225.701606)
		(width 0.088646)
		(layer "In11.Cu")
		(net "M_D_CPU0_SB_DQ<29>")
	)
	(arc
		(start 345.296236 -225.69297)
		(mid 345.022007 -225.768895)
		(end 344.745564 -225.701606)
		(width 0.088646)
		(layer "In11.Cu")
		(net "M_D_CPU0_SB_DQ<29>")
	)
	(arc
		(start 343.416636 -225.69297)
		(mid 343.142407 -225.768895)
		(end 342.865964 -225.701606)
		(width 0.088646)
		(layer "In11.Cu")
		(net "M_D_CPU0_SB_DQ<29>")
	)
	(arc
		(start 347.558868 -227.964238)
		(mid 347.737465 -227.64496)
		(end 347.558868 -227.325682)
		(width 0.088646)
		(layer "In11.Cu")
		(net "M_D_CPU0_SB_DQ<29>")
	)
	(arc
		(start 333.078582 -224.065084)
		(mid 332.959951 -224.116604)
		(end 332.83271 -224.13976)
		(width 0.088646)
		(layer "In11.Cu")
		(net "M_D_CPU0_SB_DQ<29>")
	)
	(arc
		(start 340.597236 -225.69297)
		(mid 340.323007 -225.768895)
		(end 340.046564 -225.701606)
		(width 0.088646)
		(layer "In11.Cu")
		(net "M_D_CPU0_SB_DQ<29>")
	)
	(arc
		(start 341.911432 -225.69297)
		(mid 341.724234 -225.642827)
		(end 341.537036 -225.69297)
		(width 0.088646)
		(layer "In11.Cu")
		(net "M_D_CPU0_SB_DQ<29>")
	)
	(arc
		(start 336.460084 -224.389442)
		(mid 336.412405 -224.206542)
		(end 336.281522 -224.070164)
		(width 0.088646)
		(layer "In11.Cu")
		(net "M_D_CPU0_SB_DQ<29>")
	)
	(arc
		(start 346.236036 -225.69297)
		(mid 345.961807 -225.768895)
		(end 345.685364 -225.701606)
		(width 0.088646)
		(layer "In11.Cu")
		(net "M_D_CPU0_SB_DQ<29>")
	)
	(arc
		(start 342.851232 -225.69297)
		(mid 342.664034 -225.642827)
		(end 342.476836 -225.69297)
		(width 0.088646)
		(layer "In11.Cu")
		(net "M_D_CPU0_SB_DQ<29>")
	)
	(arc
		(start 345.670632 -225.69297)
		(mid 345.483434 -225.642827)
		(end 345.296236 -225.69297)
		(width 0.088646)
		(layer "In11.Cu")
		(net "M_D_CPU0_SB_DQ<29>")
	)
	(arc
		(start 341.537036 -225.69297)
		(mid 341.262807 -225.768895)
		(end 340.986364 -225.701606)
		(width 0.088646)
		(layer "In11.Cu")
		(net "M_D_CPU0_SB_DQ<29>")
	)
	(arc
		(start 339.091778 -225.69297)
		(mid 338.90458 -225.642827)
		(end 338.717382 -225.69297)
		(width 0.088646)
		(layer "In11.Cu")
		(net "M_D_CPU0_SB_DQ<29>")
	)
	(arc
		(start 337.212432 -225.69297)
		(mid 337.008951 -225.492166)
		(end 336.92973 -225.217482)
		(width 0.088646)
		(layer "In11.Cu")
		(net "M_D_CPU0_SB_DQ<29>")
	)
	(arc
		(start 334.008222 -224.07118)
		(mid 333.72979 -224.141026)
		(end 333.452978 -224.065084)
		(width 0.088646)
		(layer "In11.Cu")
		(net "M_D_CPU0_SB_DQ<29>")
	)
	(arc
		(start 342.476836 -225.69297)
		(mid 342.202607 -225.768895)
		(end 341.926164 -225.701606)
		(width 0.088646)
		(layer "In11.Cu")
		(net "M_D_CPU0_SB_DQ<29>")
	)
	(arc
		(start 336.92973 -225.194622)
		(mid 336.87746 -225.012257)
		(end 336.742532 -224.8789)
		(width 0.088646)
		(layer "In11.Cu")
		(net "M_D_CPU0_SB_DQ<29>")
	)
	(arc
		(start 334.393032 -224.065084)
		(mid 334.205834 -224.014941)
		(end 334.018636 -224.065084)
		(width 0.088646)
		(layer "In11.Cu")
		(net "M_D_CPU0_SB_DQ<29>")
	)
	(arc
		(start 347.080332 -226.506786)
		(mid 346.875997 -226.304181)
		(end 346.797884 -226.027234)
		(width 0.088646)
		(layer "In11.Cu")
		(net "M_D_CPU0_SB_DQ<29>")
	)
	(arc
		(start 335.898236 -224.065084)
		(mid 335.615534 -224.14086)
		(end 335.332832 -224.065084)
		(width 0.088646)
		(layer "In11.Cu")
		(net "M_D_CPU0_SB_DQ<29>")
	)
	(arc
		(start 332.83271 -224.13976)
		(mid 332.814557 -224.140563)
		(end 332.796388 -224.140776)
		(width 0.088646)
		(layer "In11.Cu")
		(net "M_D_CPU0_SB_DQ<29>")
	)
	(arc
		(start 335.332832 -224.065084)
		(mid 335.145634 -224.014941)
		(end 334.958436 -224.065084)
		(width 0.088646)
		(layer "In11.Cu")
		(net "M_D_CPU0_SB_DQ<29>")
	)
	(arc
		(start 334.958436 -224.065084)
		(mid 334.675734 -224.14086)
		(end 334.393032 -224.065084)
		(width 0.088646)
		(layer "In11.Cu")
		(net "M_D_CPU0_SB_DQ<29>")
	)
	(arc
		(start 346.797884 -226.017328)
		(mid 346.750205 -225.834428)
		(end 346.619322 -225.69805)
		(width 0.088646)
		(layer "In11.Cu")
		(net "M_D_CPU0_SB_DQ<29>")
	)
	(arc
		(start 347.549978 -227.320602)
		(mid 347.347155 -227.120371)
		(end 347.267784 -226.846638)
		(width 0.088646)
		(layer "In11.Cu")
		(net "M_D_CPU0_SB_DQ<29>")
	)
	(arc
		(start 338.717382 -225.69297)
		(mid 338.440823 -225.768679)
		(end 338.162646 -225.699066)
		(width 0.088646)
		(layer "In11.Cu")
		(net "M_D_CPU0_SB_DQ<29>")
	)
	(arc
		(start 340.031832 -225.69297)
		(mid 339.844634 -225.642827)
		(end 339.657436 -225.69297)
		(width 0.088646)
		(layer "In11.Cu")
		(net "M_D_CPU0_SB_DQ<29>")
	)
	(arc
		(start 336.742532 -224.8789)
		(mid 336.538197 -224.676295)
		(end 336.460084 -224.399348)
		(width 0.088646)
		(layer "In11.Cu")
		(net "M_D_CPU0_SB_DQ<29>")
	)
	(arc
		(start 344.730832 -225.69297)
		(mid 344.543634 -225.642827)
		(end 344.356436 -225.69297)
		(width 0.088646)
		(layer "In11.Cu")
		(net "M_D_CPU0_SB_DQ<29>")
	)
	(arc
		(start 339.657436 -225.69297)
		(mid 339.380623 -225.768806)
		(end 339.102192 -225.699066)
		(width 0.088646)
		(layer "In11.Cu")
		(net "M_D_CPU0_SB_DQ<29>")
	)
	(arc
		(start 338.152232 -225.69297)
		(mid 337.965034 -225.642827)
		(end 337.777836 -225.69297)
		(width 0.088646)
		(layer "In11.Cu")
		(net "M_D_CPU0_SB_DQ<29>")
	)
	(arc
		(start 337.777836 -225.69297)
		(mid 337.503607 -225.768895)
		(end 337.227164 -225.701606)
		(width 0.088646)
		(layer "In11.Cu")
		(net "M_D_CPU0_SB_DQ<29>")
	)
	(arc
		(start 336.272632 -224.065084)
		(mid 336.085434 -224.014941)
		(end 335.898236 -224.065084)
		(width 0.088646)
		(layer "In11.Cu")
		(net "M_D_CPU0_SB_DQ<29>")
	)
	(arc
		(start 347.270832 -228.394006)
		(mid 347.359986 -228.148519)
		(end 347.549978 -227.969318)
		(width 0.088646)
		(layer "In11.Cu")
		(net "M_D_CPU0_SB_DQ<29>")
	)
	(arc
		(start 333.452978 -224.065084)
		(mid 333.26578 -224.014941)
		(end 333.078582 -224.065084)
		(width 0.088646)
		(layer "In11.Cu")
		(net "M_D_CPU0_SB_DQ<29>")
	)
	(arc
		(start 347.267784 -226.831144)
		(mid 347.220105 -226.648244)
		(end 347.089222 -226.511866)
		(width 0.088646)
		(layer "In11.Cu")
		(net "M_D_CPU0_SB_DQ<29>")
	)
	(arc
		(start 346.610432 -225.69297)
		(mid 346.423234 -225.642827)
		(end 346.236036 -225.69297)
		(width 0.088646)
		(layer "In11.Cu")
		(net "M_D_CPU0_SB_DQ<29>")
	)
	(arc
		(start 343.791032 -225.69297)
		(mid 343.603834 -225.642827)
		(end 343.416636 -225.69297)
		(width 0.088646)
		(layer "In11.Cu")
		(net "M_D_CPU0_SB_DQ<29>")
	)
	(arc
		(start 340.971632 -225.69297)
		(mid 340.784434 -225.642827)
		(end 340.597236 -225.69297)
		(width 0.088646)
		(layer "In11.Cu")
		(net "M_D_CPU0_SB_DQ<29>")
	)
	(segment
		(start 346.42298 -229.808786)
		(end 346.423234 -229.808532)
		(width 0.20066)
		(layer "F.Cu")
		(net "M_D_CPU0_SB_DQ<28>")
	)
	(segment
		(start 259.064506 -197.741794)
		(end 259.056378 -197.733666)
		(width 0.101854)
		(layer "F.Cu")
		(net "M_D_CPU0_SB_DQ<28>")
	)
	(segment
		(start 257.653536 -198.405496)
		(end 257.414776 -198.166736)
		(width 0.20066)
		(layer "F.Cu")
		(net "M_D_CPU0_SB_DQ<28>")
	)
	(segment
		(start 258.11226 -198.405496)
		(end 257.653536 -198.405496)
		(width 0.20066)
		(layer "F.Cu")
		(net "M_D_CPU0_SB_DQ<28>")
	)
	(segment
		(start 259.056378 -197.733666)
		(end 258.49453 -197.733666)
		(width 0.20066)
		(layer "F.Cu")
		(net "M_D_CPU0_SB_DQ<28>")
	)
	(segment
		(start 261.830312 -197.741794)
		(end 261.381494 -197.741794)
		(width 0.20066)
		(layer "F.Cu")
		(net "M_D_CPU0_SB_DQ<28>")
	)
	(segment
		(start 259.31241 -197.741794)
		(end 259.064506 -197.741794)
		(width 0.101854)
		(layer "F.Cu")
		(net "M_D_CPU0_SB_DQ<28>")
	)
	(segment
		(start 258.49453 -197.733666)
		(end 258.28498 -197.943216)
		(width 0.20066)
		(layer "F.Cu")
		(net "M_D_CPU0_SB_DQ<28>")
	)
	(segment
		(start 261.381494 -197.741794)
		(end 259.31241 -197.741794)
		(width 0.1016)
		(layer "F.Cu")
		(net "M_D_CPU0_SB_DQ<28>")
	)
	(segment
		(start 346.423234 -229.808532)
		(end 346.423234 -229.272846)
		(width 0.20066)
		(layer "F.Cu")
		(net "M_D_CPU0_SB_DQ<28>")
	)
	(segment
		(start 263.624314 -198.166736)
		(end 262.255254 -198.166736)
		(width 0.20066)
		(layer "F.Cu")
		(net "M_D_CPU0_SB_DQ<28>")
	)
	(segment
		(start 258.28498 -197.943216)
		(end 258.28498 -198.232776)
		(width 0.20066)
		(layer "F.Cu")
		(net "M_D_CPU0_SB_DQ<28>")
	)
	(segment
		(start 264.729214 -198.166736)
		(end 263.624314 -198.166736)
		(width 0.20066)
		(layer "F.Cu")
		(net "M_D_CPU0_SB_DQ<28>")
	)
	(segment
		(start 257.414776 -198.166736)
		(end 256.080514 -198.166736)
		(width 0.20066)
		(layer "F.Cu")
		(net "M_D_CPU0_SB_DQ<28>")
	)
	(segment
		(start 258.28498 -198.232776)
		(end 258.11226 -198.405496)
		(width 0.20066)
		(layer "F.Cu")
		(net "M_D_CPU0_SB_DQ<28>")
	)
	(segment
		(start 262.255254 -198.166736)
		(end 261.830312 -197.741794)
		(width 0.20066)
		(layer "F.Cu")
		(net "M_D_CPU0_SB_DQ<28>")
	)
	(segment
		(start 316.573916 -204.370178)
		(end 314.04941 -199.429878)
		(width 0.18288)
		(layer "In11.Cu")
		(net "M_D_CPU0_SB_DQ<28>")
	)
	(segment
		(start 299.805598 -196.039486)
		(end 293.390066 -196.039486)
		(width 0.18288)
		(layer "In11.Cu")
		(net "M_D_CPU0_SB_DQ<28>")
	)
	(segment
		(start 299.934122 -196.16801)
		(end 299.805598 -196.039486)
		(width 0.18288)
		(layer "In11.Cu")
		(net "M_D_CPU0_SB_DQ<28>")
	)
	(segment
		(start 277.995126 -196.22643)
		(end 277.156418 -196.22643)
		(width 0.18288)
		(layer "In11.Cu")
		(net "M_D_CPU0_SB_DQ<28>")
	)
	(segment
		(start 269.357094 -197.742556)
		(end 267.806424 -197.742556)
		(width 0.18288)
		(layer "In11.Cu")
		(net "M_D_CPU0_SB_DQ<28>")
	)
	(segment
		(start 303.727358 -196.255386)
		(end 301.901606 -196.255386)
		(width 0.18288)
		(layer "In11.Cu")
		(net "M_D_CPU0_SB_DQ<28>")
	)
	(segment
		(start 272.907252 -196.747892)
		(end 271.927828 -196.747892)
		(width 0.18288)
		(layer "In11.Cu")
		(net "M_D_CPU0_SB_DQ<28>")
	)
	(segment
		(start 276.959568 -196.02958)
		(end 273.625564 -196.02958)
		(width 0.18288)
		(layer "In11.Cu")
		(net "M_D_CPU0_SB_DQ<28>")
	)
	(segment
		(start 338.247482 -226.506786)
		(end 338.23275 -226.515422)
		(width 0.088646)
		(layer "In11.Cu")
		(net "M_D_CPU0_SB_DQ<28>")
	)
	(segment
		(start 336.460084 -226.032822)
		(end 336.460084 -226.017328)
		(width 0.088646)
		(layer "In11.Cu")
		(net "M_D_CPU0_SB_DQ<28>")
	)
	(segment
		(start 341.066882 -226.506786)
		(end 341.05215 -226.515422)
		(width 0.088646)
		(layer "In11.Cu")
		(net "M_D_CPU0_SB_DQ<28>")
	)
	(segment
		(start 346.610432 -229.085648)
		(end 346.610432 -228.948234)
		(width 0.088646)
		(layer "In11.Cu")
		(net "M_D_CPU0_SB_DQ<28>")
	)
	(segment
		(start 344.826082 -226.506786)
		(end 344.815668 -226.512882)
		(width 0.088646)
		(layer "In11.Cu")
		(net "M_D_CPU0_SB_DQ<28>")
	)
	(segment
		(start 332.43901 -224.828354)
		(end 331.177646 -223.56699)
		(width 0.088646)
		(layer "In11.Cu")
		(net "M_D_CPU0_SB_DQ<28>")
	)
	(segment
		(start 324.293992 -216.318846)
		(end 324.293992 -212.090254)
		(width 0.18288)
		(layer "In11.Cu")
		(net "M_D_CPU0_SB_DQ<28>")
	)
	(segment
		(start 293.250874 -196.178678)
		(end 292.226746 -196.178678)
		(width 0.18288)
		(layer "In11.Cu")
		(net "M_D_CPU0_SB_DQ<28>")
	)
	(segment
		(start 278.181816 -196.03974)
		(end 277.995126 -196.22643)
		(width 0.18288)
		(layer "In11.Cu")
		(net "M_D_CPU0_SB_DQ<28>")
	)
	(segment
		(start 330.537566 -221.993714)
		(end 329.96886 -221.993714)
		(width 0.18288)
		(layer "In11.Cu")
		(net "M_D_CPU0_SB_DQ<28>")
	)
	(segment
		(start 273.625564 -196.02958)
		(end 272.907252 -196.747892)
		(width 0.18288)
		(layer "In11.Cu")
		(net "M_D_CPU0_SB_DQ<28>")
	)
	(segment
		(start 301.81423 -196.16801)
		(end 299.934122 -196.16801)
		(width 0.18288)
		(layer "In11.Cu")
		(net "M_D_CPU0_SB_DQ<28>")
	)
	(segment
		(start 342.946482 -226.506786)
		(end 342.93175 -226.515422)
		(width 0.088646)
		(layer "In11.Cu")
		(net "M_D_CPU0_SB_DQ<28>")
	)
	(segment
		(start 336.281522 -225.69805)
		(end 336.272632 -225.69297)
		(width 0.088646)
		(layer "In11.Cu")
		(net "M_D_CPU0_SB_DQ<28>")
	)
	(segment
		(start 346.140532 -226.50704)
		(end 346.140278 -226.506786)
		(width 0.088646)
		(layer "In11.Cu")
		(net "M_D_CPU0_SB_DQ<28>")
	)
	(segment
		(start 301.901606 -196.255386)
		(end 301.81423 -196.16801)
		(width 0.18288)
		(layer "In11.Cu")
		(net "M_D_CPU0_SB_DQ<28>")
	)
	(segment
		(start 277.156418 -196.22643)
		(end 276.959568 -196.02958)
		(width 0.18288)
		(layer "In11.Cu")
		(net "M_D_CPU0_SB_DQ<28>")
	)
	(segment
		(start 342.006682 -226.506786)
		(end 341.99195 -226.515422)
		(width 0.088646)
		(layer "In11.Cu")
		(net "M_D_CPU0_SB_DQ<28>")
	)
	(segment
		(start 304.043588 -195.939156)
		(end 303.727358 -196.255386)
		(width 0.18288)
		(layer "In11.Cu")
		(net "M_D_CPU0_SB_DQ<28>")
	)
	(segment
		(start 331.177646 -222.516954)
		(end 330.654406 -221.993714)
		(width 0.088646)
		(layer "In11.Cu")
		(net "M_D_CPU0_SB_DQ<28>")
	)
	(segment
		(start 267.477494 -197.413626)
		(end 265.482324 -197.413626)
		(width 0.18288)
		(layer "In11.Cu")
		(net "M_D_CPU0_SB_DQ<28>")
	)
	(segment
		(start 346.423234 -229.272846)
		(end 346.610432 -229.085648)
		(width 0.088646)
		(layer "In11.Cu")
		(net "M_D_CPU0_SB_DQ<28>")
	)
	(segment
		(start 310.631078 -196.824346)
		(end 307.530754 -196.824346)
		(width 0.18288)
		(layer "In11.Cu")
		(net "M_D_CPU0_SB_DQ<28>")
	)
	(segment
		(start 345.766136 -226.506786)
		(end 345.765628 -226.506786)
		(width 0.088646)
		(layer "In11.Cu")
		(net "M_D_CPU0_SB_DQ<28>")
	)
	(segment
		(start 312.19267 -197.573138)
		(end 310.631078 -196.824346)
		(width 0.18288)
		(layer "In11.Cu")
		(net "M_D_CPU0_SB_DQ<28>")
	)
	(segment
		(start 282.410408 -196.03974)
		(end 278.181816 -196.03974)
		(width 0.18288)
		(layer "In11.Cu")
		(net "M_D_CPU0_SB_DQ<28>")
	)
	(segment
		(start 324.293992 -212.090254)
		(end 316.573916 -204.370178)
		(width 0.18288)
		(layer "In11.Cu")
		(net "M_D_CPU0_SB_DQ<28>")
	)
	(segment
		(start 346.79763 -227.645214)
		(end 346.79763 -227.64496)
		(width 0.088646)
		(layer "In11.Cu")
		(net "M_D_CPU0_SB_DQ<28>")
	)
	(segment
		(start 338.632292 -226.512882)
		(end 338.621878 -226.506786)
		(width 0.088646)
		(layer "In11.Cu")
		(net "M_D_CPU0_SB_DQ<28>")
	)
	(segment
		(start 335.990184 -225.2218)
		(end 335.990184 -225.203258)
		(width 0.088646)
		(layer "In11.Cu")
		(net "M_D_CPU0_SB_DQ<28>")
	)
	(segment
		(start 265.482324 -197.413626)
		(end 264.729214 -198.166736)
		(width 0.18288)
		(layer "In11.Cu")
		(net "M_D_CPU0_SB_DQ<28>")
	)
	(segment
		(start 335.811622 -224.88398)
		(end 335.802732 -224.8789)
		(width 0.088646)
		(layer "In11.Cu")
		(net "M_D_CPU0_SB_DQ<28>")
	)
	(segment
		(start 288.121852 -196.773292)
		(end 284.925516 -196.773292)
		(width 0.18288)
		(layer "In11.Cu")
		(net "M_D_CPU0_SB_DQ<28>")
	)
	(segment
		(start 343.886536 -226.506786)
		(end 343.876122 -226.512882)
		(width 0.088646)
		(layer "In11.Cu")
		(net "M_D_CPU0_SB_DQ<28>")
	)
	(segment
		(start 330.654406 -221.993714)
		(end 330.537566 -221.993714)
		(width 0.088646)
		(layer "In11.Cu")
		(net "M_D_CPU0_SB_DQ<28>")
	)
	(segment
		(start 340.127082 -226.506786)
		(end 340.116668 -226.512882)
		(width 0.088646)
		(layer "In11.Cu")
		(net "M_D_CPU0_SB_DQ<28>")
	)
	(segment
		(start 284.807914 -196.890894)
		(end 283.261562 -196.890894)
		(width 0.18288)
		(layer "In11.Cu")
		(net "M_D_CPU0_SB_DQ<28>")
	)
	(segment
		(start 331.177646 -223.56699)
		(end 331.177646 -222.516954)
		(width 0.088646)
		(layer "In11.Cu")
		(net "M_D_CPU0_SB_DQ<28>")
	)
	(segment
		(start 346.32773 -228.45903)
		(end 346.32773 -228.444806)
		(width 0.088646)
		(layer "In11.Cu")
		(net "M_D_CPU0_SB_DQ<28>")
	)
	(segment
		(start 329.96886 -221.993714)
		(end 324.293992 -216.318846)
		(width 0.18288)
		(layer "In11.Cu")
		(net "M_D_CPU0_SB_DQ<28>")
	)
	(segment
		(start 283.261562 -196.890894)
		(end 282.410408 -196.03974)
		(width 0.18288)
		(layer "In11.Cu")
		(net "M_D_CPU0_SB_DQ<28>")
	)
	(segment
		(start 267.806424 -197.742556)
		(end 267.477494 -197.413626)
		(width 0.18288)
		(layer "In11.Cu")
		(net "M_D_CPU0_SB_DQ<28>")
	)
	(segment
		(start 307.530754 -196.824346)
		(end 306.645564 -195.939156)
		(width 0.18288)
		(layer "In11.Cu")
		(net "M_D_CPU0_SB_DQ<28>")
	)
	(segment
		(start 332.998064 -224.887536)
		(end 332.983332 -224.8789)
		(width 0.088646)
		(layer "In11.Cu")
		(net "M_D_CPU0_SB_DQ<28>")
	)
	(segment
		(start 306.645564 -195.939156)
		(end 304.043588 -195.939156)
		(width 0.18288)
		(layer "In11.Cu")
		(net "M_D_CPU0_SB_DQ<28>")
	)
	(segment
		(start 284.925516 -196.773292)
		(end 284.807914 -196.890894)
		(width 0.18288)
		(layer "In11.Cu")
		(net "M_D_CPU0_SB_DQ<28>")
	)
	(segment
		(start 270.677894 -197.997826)
		(end 269.612364 -197.997826)
		(width 0.18288)
		(layer "In11.Cu")
		(net "M_D_CPU0_SB_DQ<28>")
	)
	(segment
		(start 271.927828 -196.747892)
		(end 270.677894 -197.997826)
		(width 0.18288)
		(layer "In11.Cu")
		(net "M_D_CPU0_SB_DQ<28>")
	)
	(segment
		(start 292.226746 -196.178678)
		(end 291.886894 -195.838826)
		(width 0.18288)
		(layer "In11.Cu")
		(net "M_D_CPU0_SB_DQ<28>")
	)
	(segment
		(start 289.056318 -195.838826)
		(end 288.121852 -196.773292)
		(width 0.18288)
		(layer "In11.Cu")
		(net "M_D_CPU0_SB_DQ<28>")
	)
	(segment
		(start 332.796134 -224.828354)
		(end 332.43901 -224.828354)
		(width 0.088646)
		(layer "In11.Cu")
		(net "M_D_CPU0_SB_DQ<28>")
	)
	(segment
		(start 269.612364 -197.997826)
		(end 269.357094 -197.742556)
		(width 0.18288)
		(layer "In11.Cu")
		(net "M_D_CPU0_SB_DQ<28>")
	)
	(segment
		(start 291.886894 -195.838826)
		(end 289.056318 -195.838826)
		(width 0.18288)
		(layer "In11.Cu")
		(net "M_D_CPU0_SB_DQ<28>")
	)
	(segment
		(start 346.610432 -227.320602)
		(end 346.610432 -227.320348)
		(width 0.088646)
		(layer "In11.Cu")
		(net "M_D_CPU0_SB_DQ<28>")
	)
	(segment
		(start 314.04941 -199.429878)
		(end 312.19267 -197.573138)
		(width 0.18288)
		(layer "In11.Cu")
		(net "M_D_CPU0_SB_DQ<28>")
	)
	(segment
		(start 293.390066 -196.039486)
		(end 293.250874 -196.178678)
		(width 0.18288)
		(layer "In11.Cu")
		(net "M_D_CPU0_SB_DQ<28>")
	)
	(segment
		(start 337.307682 -226.506786)
		(end 337.29295 -226.515422)
		(width 0.088646)
		(layer "In11.Cu")
		(net "M_D_CPU0_SB_DQ<28>")
	)
	(arc
		(start 343.876122 -226.512882)
		(mid 343.59769 -226.582728)
		(end 343.320878 -226.506786)
		(width 0.088646)
		(layer "In11.Cu")
		(net "M_D_CPU0_SB_DQ<28>")
	)
	(arc
		(start 346.610432 -227.969318)
		(mid 346.747477 -227.832358)
		(end 346.79763 -227.645214)
		(width 0.088646)
		(layer "In11.Cu")
		(net "M_D_CPU0_SB_DQ<28>")
	)
	(arc
		(start 333.923132 -224.8789)
		(mid 333.735934 -224.828757)
		(end 333.548736 -224.8789)
		(width 0.088646)
		(layer "In11.Cu")
		(net "M_D_CPU0_SB_DQ<28>")
	)
	(arc
		(start 340.501478 -226.506786)
		(mid 340.31428 -226.456643)
		(end 340.127082 -226.506786)
		(width 0.088646)
		(layer "In11.Cu")
		(net "M_D_CPU0_SB_DQ<28>")
	)
	(arc
		(start 346.610432 -227.320348)
		(mid 346.403577 -227.113606)
		(end 346.32773 -226.831144)
		(width 0.088646)
		(layer "In11.Cu")
		(net "M_D_CPU0_SB_DQ<28>")
	)
	(arc
		(start 338.621878 -226.506786)
		(mid 338.43468 -226.456643)
		(end 338.247482 -226.506786)
		(width 0.088646)
		(layer "In11.Cu")
		(net "M_D_CPU0_SB_DQ<28>")
	)
	(arc
		(start 346.79763 -227.64496)
		(mid 346.747476 -227.457704)
		(end 346.610432 -227.320602)
		(width 0.088646)
		(layer "In11.Cu")
		(net "M_D_CPU0_SB_DQ<28>")
	)
	(arc
		(start 336.460084 -226.017328)
		(mid 336.412405 -225.834428)
		(end 336.281522 -225.69805)
		(width 0.088646)
		(layer "In11.Cu")
		(net "M_D_CPU0_SB_DQ<28>")
	)
	(arc
		(start 341.05215 -226.515422)
		(mid 340.775675 -226.582742)
		(end 340.501478 -226.506786)
		(width 0.088646)
		(layer "In11.Cu")
		(net "M_D_CPU0_SB_DQ<28>")
	)
	(arc
		(start 346.610432 -228.948234)
		(mid 346.403488 -228.741524)
		(end 346.32773 -228.45903)
		(width 0.088646)
		(layer "In11.Cu")
		(net "M_D_CPU0_SB_DQ<28>")
	)
	(arc
		(start 335.990184 -225.203258)
		(mid 335.942505 -225.020358)
		(end 335.811622 -224.88398)
		(width 0.088646)
		(layer "In11.Cu")
		(net "M_D_CPU0_SB_DQ<28>")
	)
	(arc
		(start 336.272632 -225.69297)
		(mid 336.070346 -225.493989)
		(end 335.990184 -225.2218)
		(width 0.088646)
		(layer "In11.Cu")
		(net "M_D_CPU0_SB_DQ<28>")
	)
	(arc
		(start 339.561932 -226.506786)
		(mid 339.374734 -226.456643)
		(end 339.187536 -226.506786)
		(width 0.088646)
		(layer "In11.Cu")
		(net "M_D_CPU0_SB_DQ<28>")
	)
	(arc
		(start 335.428336 -224.8789)
		(mid 335.145634 -224.954676)
		(end 334.862932 -224.8789)
		(width 0.088646)
		(layer "In11.Cu")
		(net "M_D_CPU0_SB_DQ<28>")
	)
	(arc
		(start 342.381078 -226.506786)
		(mid 342.19388 -226.456643)
		(end 342.006682 -226.506786)
		(width 0.088646)
		(layer "In11.Cu")
		(net "M_D_CPU0_SB_DQ<28>")
	)
	(arc
		(start 339.187536 -226.506786)
		(mid 338.910723 -226.582656)
		(end 338.632292 -226.512882)
		(width 0.088646)
		(layer "In11.Cu")
		(net "M_D_CPU0_SB_DQ<28>")
	)
	(arc
		(start 345.765628 -226.506786)
		(mid 345.48307 -226.582435)
		(end 345.200478 -226.506786)
		(width 0.088646)
		(layer "In11.Cu")
		(net "M_D_CPU0_SB_DQ<28>")
	)
	(arc
		(start 346.140278 -226.506786)
		(mid 345.953224 -226.456736)
		(end 345.766136 -226.506786)
		(width 0.088646)
		(layer "In11.Cu")
		(net "M_D_CPU0_SB_DQ<28>")
	)
	(arc
		(start 338.23275 -226.515422)
		(mid 337.956275 -226.582742)
		(end 337.682078 -226.506786)
		(width 0.088646)
		(layer "In11.Cu")
		(net "M_D_CPU0_SB_DQ<28>")
	)
	(arc
		(start 340.116668 -226.512882)
		(mid 339.83849 -226.582605)
		(end 339.561932 -226.506786)
		(width 0.088646)
		(layer "In11.Cu")
		(net "M_D_CPU0_SB_DQ<28>")
	)
	(arc
		(start 344.260932 -226.506786)
		(mid 344.073734 -226.456643)
		(end 343.886536 -226.506786)
		(width 0.088646)
		(layer "In11.Cu")
		(net "M_D_CPU0_SB_DQ<28>")
	)
	(arc
		(start 335.802732 -224.8789)
		(mid 335.615534 -224.828757)
		(end 335.428336 -224.8789)
		(width 0.088646)
		(layer "In11.Cu")
		(net "M_D_CPU0_SB_DQ<28>")
	)
	(arc
		(start 346.32773 -228.444806)
		(mid 346.406949 -228.170121)
		(end 346.610432 -227.969318)
		(width 0.088646)
		(layer "In11.Cu")
		(net "M_D_CPU0_SB_DQ<28>")
	)
	(arc
		(start 333.548736 -224.8789)
		(mid 333.274537 -224.954735)
		(end 332.998064 -224.887536)
		(width 0.088646)
		(layer "In11.Cu")
		(net "M_D_CPU0_SB_DQ<28>")
	)
	(arc
		(start 336.742278 -226.506786)
		(mid 336.539455 -226.306555)
		(end 336.460084 -226.032822)
		(width 0.088646)
		(layer "In11.Cu")
		(net "M_D_CPU0_SB_DQ<28>")
	)
	(arc
		(start 334.488536 -224.8789)
		(mid 334.205834 -224.954676)
		(end 333.923132 -224.8789)
		(width 0.088646)
		(layer "In11.Cu")
		(net "M_D_CPU0_SB_DQ<28>")
	)
	(arc
		(start 332.983332 -224.8789)
		(mid 332.89306 -224.841301)
		(end 332.796134 -224.828354)
		(width 0.088646)
		(layer "In11.Cu")
		(net "M_D_CPU0_SB_DQ<28>")
	)
	(arc
		(start 341.99195 -226.515422)
		(mid 341.715475 -226.582742)
		(end 341.441278 -226.506786)
		(width 0.088646)
		(layer "In11.Cu")
		(net "M_D_CPU0_SB_DQ<28>")
	)
	(arc
		(start 341.441278 -226.506786)
		(mid 341.25408 -226.456643)
		(end 341.066882 -226.506786)
		(width 0.088646)
		(layer "In11.Cu")
		(net "M_D_CPU0_SB_DQ<28>")
	)
	(arc
		(start 342.93175 -226.515422)
		(mid 342.655275 -226.582742)
		(end 342.381078 -226.506786)
		(width 0.088646)
		(layer "In11.Cu")
		(net "M_D_CPU0_SB_DQ<28>")
	)
	(arc
		(start 337.682078 -226.506786)
		(mid 337.49488 -226.456643)
		(end 337.307682 -226.506786)
		(width 0.088646)
		(layer "In11.Cu")
		(net "M_D_CPU0_SB_DQ<28>")
	)
	(arc
		(start 346.32773 -226.831144)
		(mid 346.277566 -226.644006)
		(end 346.140532 -226.50704)
		(width 0.088646)
		(layer "In11.Cu")
		(net "M_D_CPU0_SB_DQ<28>")
	)
	(arc
		(start 337.29295 -226.515422)
		(mid 337.016475 -226.582742)
		(end 336.742278 -226.506786)
		(width 0.088646)
		(layer "In11.Cu")
		(net "M_D_CPU0_SB_DQ<28>")
	)
	(arc
		(start 343.320878 -226.506786)
		(mid 343.13368 -226.456643)
		(end 342.946482 -226.506786)
		(width 0.088646)
		(layer "In11.Cu")
		(net "M_D_CPU0_SB_DQ<28>")
	)
	(arc
		(start 334.862932 -224.8789)
		(mid 334.675734 -224.828757)
		(end 334.488536 -224.8789)
		(width 0.088646)
		(layer "In11.Cu")
		(net "M_D_CPU0_SB_DQ<28>")
	)
	(arc
		(start 345.200478 -226.506786)
		(mid 345.01328 -226.456643)
		(end 344.826082 -226.506786)
		(width 0.088646)
		(layer "In11.Cu")
		(net "M_D_CPU0_SB_DQ<28>")
	)
	(arc
		(start 344.815668 -226.512882)
		(mid 344.53749 -226.582605)
		(end 344.260932 -226.506786)
		(width 0.088646)
		(layer "In11.Cu")
		(net "M_D_CPU0_SB_DQ<28>")
	)
	(segment
		(start 265.369548 -201.991722)
		(end 264.825226 -201.991722)
		(width 0.20066)
		(layer "F.Cu")
		(net "M_D_CPU0_SB_DQ<27>")
	)
	(segment
		(start 268.829282 -201.56678)
		(end 267.724382 -201.56678)
		(width 0.20066)
		(layer "F.Cu")
		(net "M_D_CPU0_SB_DQ<27>")
	)
	(segment
		(start 267.724382 -201.56678)
		(end 266.90828 -201.56678)
		(width 0.20066)
		(layer "F.Cu")
		(net "M_D_CPU0_SB_DQ<27>")
	)
	(segment
		(start 266.700762 -201.774298)
		(end 266.25423 -201.774298)
		(width 0.20066)
		(layer "F.Cu")
		(net "M_D_CPU0_SB_DQ<27>")
	)
	(segment
		(start 265.518646 -201.690986)
		(end 265.518646 -201.842624)
		(width 0.20066)
		(layer "F.Cu")
		(net "M_D_CPU0_SB_DQ<27>")
	)
	(segment
		(start 262.146288 -202.005946)
		(end 262.003794 -201.863452)
		(width 0.20066)
		(layer "F.Cu")
		(net "M_D_CPU0_SB_DQ<27>")
	)
	(segment
		(start 266.042394 -201.562462)
		(end 265.64717 -201.562462)
		(width 0.20066)
		(layer "F.Cu")
		(net "M_D_CPU0_SB_DQ<27>")
	)
	(segment
		(start 264.825226 -201.991722)
		(end 262.752332 -201.991722)
		(width 0.1016)
		(layer "F.Cu")
		(net "M_D_CPU0_SB_DQ<27>")
	)
	(segment
		(start 266.90828 -201.56678)
		(end 266.700762 -201.774298)
		(width 0.20066)
		(layer "F.Cu")
		(net "M_D_CPU0_SB_DQ<27>")
	)
	(segment
		(start 265.518646 -201.842624)
		(end 265.369548 -201.991722)
		(width 0.20066)
		(layer "F.Cu")
		(net "M_D_CPU0_SB_DQ<27>")
	)
	(segment
		(start 261.87781 -201.56678)
		(end 260.180582 -201.56678)
		(width 0.20066)
		(layer "F.Cu")
		(net "M_D_CPU0_SB_DQ<27>")
	)
	(segment
		(start 262.003794 -201.692764)
		(end 261.87781 -201.56678)
		(width 0.20066)
		(layer "F.Cu")
		(net "M_D_CPU0_SB_DQ<27>")
	)
	(segment
		(start 348.30258 -231.436418)
		(end 348.302834 -231.436164)
		(width 0.20066)
		(layer "F.Cu")
		(net "M_D_CPU0_SB_DQ<27>")
	)
	(segment
		(start 262.50011 -202.005946)
		(end 262.146288 -202.005946)
		(width 0.20066)
		(layer "F.Cu")
		(net "M_D_CPU0_SB_DQ<27>")
	)
	(segment
		(start 262.514334 -201.991722)
		(end 262.50011 -202.005946)
		(width 0.101854)
		(layer "F.Cu")
		(net "M_D_CPU0_SB_DQ<27>")
	)
	(segment
		(start 265.64717 -201.562462)
		(end 265.518646 -201.690986)
		(width 0.20066)
		(layer "F.Cu")
		(net "M_D_CPU0_SB_DQ<27>")
	)
	(segment
		(start 262.003794 -201.863452)
		(end 262.003794 -201.692764)
		(width 0.20066)
		(layer "F.Cu")
		(net "M_D_CPU0_SB_DQ<27>")
	)
	(segment
		(start 266.25423 -201.774298)
		(end 266.042394 -201.562462)
		(width 0.20066)
		(layer "F.Cu")
		(net "M_D_CPU0_SB_DQ<27>")
	)
	(segment
		(start 262.752332 -201.991722)
		(end 262.514334 -201.991722)
		(width 0.101854)
		(layer "F.Cu")
		(net "M_D_CPU0_SB_DQ<27>")
	)
	(segment
		(start 348.302834 -231.436164)
		(end 348.302834 -230.900478)
		(width 0.20066)
		(layer "F.Cu")
		(net "M_D_CPU0_SB_DQ<27>")
	)
	(segment
		(start 289.908996 -201.157586)
		(end 289.715956 -201.350626)
		(width 0.18288)
		(layer "In11.Cu")
		(net "M_D_CPU0_SB_DQ<27>")
	)
	(segment
		(start 305.395122 -200.16978)
		(end 305.202082 -200.36282)
		(width 0.18288)
		(layer "In11.Cu")
		(net "M_D_CPU0_SB_DQ<27>")
	)
	(segment
		(start 287.015428 -201.122026)
		(end 286.502094 -201.122026)
		(width 0.18288)
		(layer "In11.Cu")
		(net "M_D_CPU0_SB_DQ<27>")
	)
	(segment
		(start 321.510914 -213.89848)
		(end 312.248804 -204.63637)
		(width 0.18288)
		(layer "In11.Cu")
		(net "M_D_CPU0_SB_DQ<27>")
	)
	(segment
		(start 275.550884 -200.744582)
		(end 275.357844 -200.551542)
		(width 0.18288)
		(layer "In11.Cu")
		(net "M_D_CPU0_SB_DQ<27>")
	)
	(segment
		(start 330.980034 -226.245674)
		(end 330.434442 -225.700082)
		(width 0.088646)
		(layer "In11.Cu")
		(net "M_D_CPU0_SB_DQ<27>")
	)
	(segment
		(start 290.610036 -200.674986)
		(end 290.416996 -200.481946)
		(width 0.18288)
		(layer "In11.Cu")
		(net "M_D_CPU0_SB_DQ<27>")
	)
	(segment
		(start 293.786306 -201.144124)
		(end 293.495476 -200.853294)
		(width 0.18288)
		(layer "In11.Cu")
		(net "M_D_CPU0_SB_DQ<27>")
	)
	(segment
		(start 344.826336 -230.41102)
		(end 344.817446 -230.40594)
		(width 0.088646)
		(layer "In11.Cu")
		(net "M_D_CPU0_SB_DQ<27>")
	)
	(segment
		(start 278.388064 -200.849992)
		(end 278.388064 -200.536556)
		(width 0.18288)
		(layer "In11.Cu")
		(net "M_D_CPU0_SB_DQ<27>")
	)
	(segment
		(start 286.502094 -201.122026)
		(end 285.518352 -202.105768)
		(width 0.18288)
		(layer "In11.Cu")
		(net "M_D_CPU0_SB_DQ<27>")
	)
	(segment
		(start 310.860694 -203.382626)
		(end 308.422294 -200.944226)
		(width 0.18288)
		(layer "In11.Cu")
		(net "M_D_CPU0_SB_DQ<27>")
	)
	(segment
		(start 307.030628 -201.269092)
		(end 306.096162 -201.269092)
		(width 0.18288)
		(layer "In11.Cu")
		(net "M_D_CPU0_SB_DQ<27>")
	)
	(segment
		(start 275.550884 -201.157586)
		(end 275.550884 -200.744582)
		(width 0.18288)
		(layer "In11.Cu")
		(net "M_D_CPU0_SB_DQ<27>")
	)
	(segment
		(start 336.367882 -228.783388)
		(end 336.357468 -228.777292)
		(width 0.088646)
		(layer "In11.Cu")
		(net "M_D_CPU0_SB_DQ<27>")
	)
	(segment
		(start 288.753804 -201.122026)
		(end 288.102548 -201.122026)
		(width 0.18288)
		(layer "In11.Cu")
		(net "M_D_CPU0_SB_DQ<27>")
	)
	(segment
		(start 311.428638 -204.63637)
		(end 310.860694 -204.068426)
		(width 0.18288)
		(layer "In11.Cu")
		(net "M_D_CPU0_SB_DQ<27>")
	)
	(segment
		(start 292.079426 -200.853294)
		(end 291.582094 -201.350626)
		(width 0.18288)
		(layer "In11.Cu")
		(net "M_D_CPU0_SB_DQ<27>")
	)
	(segment
		(start 273.725894 -201.350626)
		(end 273.497294 -201.122026)
		(width 0.18288)
		(layer "In11.Cu")
		(net "M_D_CPU0_SB_DQ<27>")
	)
	(segment
		(start 278.195024 -200.343516)
		(end 277.880064 -200.343516)
		(width 0.18288)
		(layer "In11.Cu")
		(net "M_D_CPU0_SB_DQ<27>")
	)
	(segment
		(start 271.121378 -202.034902)
		(end 269.297404 -202.034902)
		(width 0.18288)
		(layer "In11.Cu")
		(net "M_D_CPU0_SB_DQ<27>")
	)
	(segment
		(start 287.208468 -200.928986)
		(end 287.015428 -201.122026)
		(width 0.18288)
		(layer "In11.Cu")
		(net "M_D_CPU0_SB_DQ<27>")
	)
	(segment
		(start 293.495476 -200.853294)
		(end 292.079426 -200.853294)
		(width 0.18288)
		(layer "In11.Cu")
		(net "M_D_CPU0_SB_DQ<27>")
	)
	(segment
		(start 301.462694 -201.426826)
		(end 300.895258 -201.994262)
		(width 0.18288)
		(layer "In11.Cu")
		(net "M_D_CPU0_SB_DQ<27>")
	)
	(segment
		(start 332.993492 -227.149406)
		(end 332.983078 -227.155502)
		(width 0.088646)
		(layer "In11.Cu")
		(net "M_D_CPU0_SB_DQ<27>")
	)
	(segment
		(start 298.19473 -201.994262)
		(end 297.344592 -201.144124)
		(width 0.18288)
		(layer "In11.Cu")
		(net "M_D_CPU0_SB_DQ<27>")
	)
	(segment
		(start 274.656804 -201.350626)
		(end 273.725894 -201.350626)
		(width 0.18288)
		(layer "In11.Cu")
		(net "M_D_CPU0_SB_DQ<27>")
	)
	(segment
		(start 283.079952 -201.992484)
		(end 282.425902 -201.338434)
		(width 0.18288)
		(layer "In11.Cu")
		(net "M_D_CPU0_SB_DQ<27>")
	)
	(segment
		(start 334.770984 -227.653596)
		(end 334.770984 -227.64496)
		(width 0.088646)
		(layer "In11.Cu")
		(net "M_D_CPU0_SB_DQ<27>")
	)
	(segment
		(start 269.297404 -202.034902)
		(end 268.829282 -201.56678)
		(width 0.18288)
		(layer "In11.Cu")
		(net "M_D_CPU0_SB_DQ<27>")
	)
	(segment
		(start 342.006682 -228.783388)
		(end 341.99195 -228.774752)
		(width 0.088646)
		(layer "In11.Cu")
		(net "M_D_CPU0_SB_DQ<27>")
	)
	(segment
		(start 330.434442 -225.700082)
		(end 321.510914 -216.776554)
		(width 0.18288)
		(layer "In11.Cu")
		(net "M_D_CPU0_SB_DQ<27>")
	)
	(segment
		(start 282.425902 -201.338434)
		(end 280.905712 -201.338434)
		(width 0.18288)
		(layer "In11.Cu")
		(net "M_D_CPU0_SB_DQ<27>")
	)
	(segment
		(start 290.416996 -200.481946)
		(end 290.102036 -200.481946)
		(width 0.18288)
		(layer "In11.Cu")
		(net "M_D_CPU0_SB_DQ<27>")
	)
	(segment
		(start 275.743924 -201.350626)
		(end 275.550884 -201.157586)
		(width 0.18288)
		(layer "In11.Cu")
		(net "M_D_CPU0_SB_DQ<27>")
	)
	(segment
		(start 280.905712 -201.338434)
		(end 280.710386 -201.143108)
		(width 0.18288)
		(layer "In11.Cu")
		(net "M_D_CPU0_SB_DQ<27>")
	)
	(segment
		(start 306.096162 -201.269092)
		(end 305.903122 -201.076052)
		(width 0.18288)
		(layer "In11.Cu")
		(net "M_D_CPU0_SB_DQ<27>")
	)
	(segment
		(start 287.401508 -200.447148)
		(end 287.208468 -200.640188)
		(width 0.18288)
		(layer "In11.Cu")
		(net "M_D_CPU0_SB_DQ<27>")
	)
	(segment
		(start 337.307682 -228.783388)
		(end 337.29295 -228.774752)
		(width 0.088646)
		(layer "In11.Cu")
		(net "M_D_CPU0_SB_DQ<27>")
	)
	(segment
		(start 289.715956 -201.350626)
		(end 288.982404 -201.350626)
		(width 0.18288)
		(layer "In11.Cu")
		(net "M_D_CPU0_SB_DQ<27>")
	)
	(segment
		(start 290.102036 -200.481946)
		(end 289.908996 -200.674986)
		(width 0.18288)
		(layer "In11.Cu")
		(net "M_D_CPU0_SB_DQ<27>")
	)
	(segment
		(start 279.4762 -201.143108)
		(end 279.376124 -201.043032)
		(width 0.18288)
		(layer "In11.Cu")
		(net "M_D_CPU0_SB_DQ<27>")
	)
	(segment
		(start 305.009042 -201.269092)
		(end 303.817782 -201.269092)
		(width 0.18288)
		(layer "In11.Cu")
		(net "M_D_CPU0_SB_DQ<27>")
	)
	(segment
		(start 275.042884 -200.551542)
		(end 274.849844 -200.744582)
		(width 0.18288)
		(layer "In11.Cu")
		(net "M_D_CPU0_SB_DQ<27>")
	)
	(segment
		(start 341.066882 -228.783388)
		(end 341.05215 -228.774752)
		(width 0.088646)
		(layer "In11.Cu")
		(net "M_D_CPU0_SB_DQ<27>")
	)
	(segment
		(start 290.803076 -201.350626)
		(end 290.610036 -201.157586)
		(width 0.18288)
		(layer "In11.Cu")
		(net "M_D_CPU0_SB_DQ<27>")
	)
	(segment
		(start 302.522382 -200.791826)
		(end 301.887382 -201.426826)
		(width 0.18288)
		(layer "In11.Cu")
		(net "M_D_CPU0_SB_DQ<27>")
	)
	(segment
		(start 285.518352 -202.105768)
		(end 284.895036 -202.105768)
		(width 0.18288)
		(layer "In11.Cu")
		(net "M_D_CPU0_SB_DQ<27>")
	)
	(segment
		(start 303.340516 -200.791826)
		(end 302.522382 -200.791826)
		(width 0.18288)
		(layer "In11.Cu")
		(net "M_D_CPU0_SB_DQ<27>")
	)
	(segment
		(start 305.202082 -201.076052)
		(end 305.009042 -201.269092)
		(width 0.18288)
		(layer "In11.Cu")
		(net "M_D_CPU0_SB_DQ<27>")
	)
	(segment
		(start 343.886282 -228.783388)
		(end 343.87155 -228.774752)
		(width 0.088646)
		(layer "In11.Cu")
		(net "M_D_CPU0_SB_DQ<27>")
	)
	(segment
		(start 287.909508 -200.640188)
		(end 287.716468 -200.447148)
		(width 0.18288)
		(layer "In11.Cu")
		(net "M_D_CPU0_SB_DQ<27>")
	)
	(segment
		(start 276.519894 -201.350626)
		(end 275.743924 -201.350626)
		(width 0.18288)
		(layer "In11.Cu")
		(net "M_D_CPU0_SB_DQ<27>")
	)
	(segment
		(start 291.582094 -201.350626)
		(end 290.803076 -201.350626)
		(width 0.18288)
		(layer "In11.Cu")
		(net "M_D_CPU0_SB_DQ<27>")
	)
	(segment
		(start 277.687024 -200.536556)
		(end 277.687024 -200.849992)
		(width 0.18288)
		(layer "In11.Cu")
		(net "M_D_CPU0_SB_DQ<27>")
	)
	(segment
		(start 284.781752 -201.992484)
		(end 283.079952 -201.992484)
		(width 0.18288)
		(layer "In11.Cu")
		(net "M_D_CPU0_SB_DQ<27>")
	)
	(segment
		(start 340.127082 -228.783388)
		(end 340.116668 -228.777292)
		(width 0.088646)
		(layer "In11.Cu")
		(net "M_D_CPU0_SB_DQ<27>")
	)
	(segment
		(start 273.497294 -201.122026)
		(end 272.034254 -201.122026)
		(width 0.18288)
		(layer "In11.Cu")
		(net "M_D_CPU0_SB_DQ<27>")
	)
	(segment
		(start 301.887382 -201.426826)
		(end 301.462694 -201.426826)
		(width 0.18288)
		(layer "In11.Cu")
		(net "M_D_CPU0_SB_DQ<27>")
	)
	(segment
		(start 339.187536 -228.783388)
		(end 339.177122 -228.777292)
		(width 0.088646)
		(layer "In11.Cu")
		(net "M_D_CPU0_SB_DQ<27>")
	)
	(segment
		(start 345.670632 -230.57612)
		(end 345.384628 -230.411274)
		(width 0.088646)
		(layer "In11.Cu")
		(net "M_D_CPU0_SB_DQ<27>")
	)
	(segment
		(start 321.510914 -216.776554)
		(end 321.510914 -213.89848)
		(width 0.18288)
		(layer "In11.Cu")
		(net "M_D_CPU0_SB_DQ<27>")
	)
	(segment
		(start 346.610686 -230.57612)
		(end 346.610178 -230.57612)
		(width 0.088646)
		(layer "In11.Cu")
		(net "M_D_CPU0_SB_DQ<27>")
	)
	(segment
		(start 305.903122 -200.36282)
		(end 305.710082 -200.16978)
		(width 0.18288)
		(layer "In11.Cu")
		(net "M_D_CPU0_SB_DQ<27>")
	)
	(segment
		(start 275.357844 -200.551542)
		(end 275.042884 -200.551542)
		(width 0.18288)
		(layer "In11.Cu")
		(net "M_D_CPU0_SB_DQ<27>")
	)
	(segment
		(start 274.849844 -200.744582)
		(end 274.849844 -201.157586)
		(width 0.18288)
		(layer "In11.Cu")
		(net "M_D_CPU0_SB_DQ<27>")
	)
	(segment
		(start 277.880064 -200.343516)
		(end 277.687024 -200.536556)
		(width 0.18288)
		(layer "In11.Cu")
		(net "M_D_CPU0_SB_DQ<27>")
	)
	(segment
		(start 284.895036 -202.105768)
		(end 284.781752 -201.992484)
		(width 0.18288)
		(layer "In11.Cu")
		(net "M_D_CPU0_SB_DQ<27>")
	)
	(segment
		(start 288.982404 -201.350626)
		(end 288.753804 -201.122026)
		(width 0.18288)
		(layer "In11.Cu")
		(net "M_D_CPU0_SB_DQ<27>")
	)
	(segment
		(start 287.208468 -200.640188)
		(end 287.208468 -200.928986)
		(width 0.18288)
		(layer "In11.Cu")
		(net "M_D_CPU0_SB_DQ<27>")
	)
	(segment
		(start 334.494378 -227.159058)
		(end 334.488282 -227.155502)
		(width 0.088646)
		(layer "In11.Cu")
		(net "M_D_CPU0_SB_DQ<27>")
	)
	(segment
		(start 344.362532 -229.60076)
		(end 344.356436 -229.597204)
		(width 0.088646)
		(layer "In11.Cu")
		(net "M_D_CPU0_SB_DQ<27>")
	)
	(segment
		(start 347.564964 -230.584756)
		(end 347.550232 -230.57612)
		(width 0.088646)
		(layer "In11.Cu")
		(net "M_D_CPU0_SB_DQ<27>")
	)
	(segment
		(start 344.356436 -229.597204)
		(end 344.347546 -229.592124)
		(width 0.088646)
		(layer "In11.Cu")
		(net "M_D_CPU0_SB_DQ<27>")
	)
	(segment
		(start 279.376124 -201.043032)
		(end 278.581104 -201.043032)
		(width 0.18288)
		(layer "In11.Cu")
		(net "M_D_CPU0_SB_DQ<27>")
	)
	(segment
		(start 305.710082 -200.16978)
		(end 305.395122 -200.16978)
		(width 0.18288)
		(layer "In11.Cu")
		(net "M_D_CPU0_SB_DQ<27>")
	)
	(segment
		(start 278.388064 -200.536556)
		(end 278.195024 -200.343516)
		(width 0.18288)
		(layer "In11.Cu")
		(net "M_D_CPU0_SB_DQ<27>")
	)
	(segment
		(start 300.895258 -201.994262)
		(end 298.19473 -201.994262)
		(width 0.18288)
		(layer "In11.Cu")
		(net "M_D_CPU0_SB_DQ<27>")
	)
	(segment
		(start 334.488282 -227.155502)
		(end 334.477868 -227.149406)
		(width 0.088646)
		(layer "In11.Cu")
		(net "M_D_CPU0_SB_DQ<27>")
	)
	(segment
		(start 278.581104 -201.043032)
		(end 278.388064 -200.849992)
		(width 0.18288)
		(layer "In11.Cu")
		(net "M_D_CPU0_SB_DQ<27>")
	)
	(segment
		(start 305.202082 -200.36282)
		(end 305.202082 -201.076052)
		(width 0.18288)
		(layer "In11.Cu")
		(net "M_D_CPU0_SB_DQ<27>")
	)
	(segment
		(start 289.908996 -200.674986)
		(end 289.908996 -201.157586)
		(width 0.18288)
		(layer "In11.Cu")
		(net "M_D_CPU0_SB_DQ<27>")
	)
	(segment
		(start 310.860694 -204.068426)
		(end 310.860694 -203.382626)
		(width 0.18288)
		(layer "In11.Cu")
		(net "M_D_CPU0_SB_DQ<27>")
	)
	(segment
		(start 331.58049 -227.07981)
		(end 330.980034 -226.479354)
		(width 0.088646)
		(layer "In11.Cu")
		(net "M_D_CPU0_SB_DQ<27>")
	)
	(segment
		(start 307.355494 -200.944226)
		(end 307.030628 -201.269092)
		(width 0.18288)
		(layer "In11.Cu")
		(net "M_D_CPU0_SB_DQ<27>")
	)
	(segment
		(start 288.102548 -201.122026)
		(end 287.909508 -200.928986)
		(width 0.18288)
		(layer "In11.Cu")
		(net "M_D_CPU0_SB_DQ<27>")
	)
	(segment
		(start 330.980034 -226.479354)
		(end 330.980034 -226.245674)
		(width 0.088646)
		(layer "In11.Cu")
		(net "M_D_CPU0_SB_DQ<27>")
	)
	(segment
		(start 334.970374 -227.97643)
		(end 334.958182 -227.969318)
		(width 0.088646)
		(layer "In11.Cu")
		(net "M_D_CPU0_SB_DQ<27>")
	)
	(segment
		(start 338.247482 -228.783388)
		(end 338.23275 -228.774752)
		(width 0.088646)
		(layer "In11.Cu")
		(net "M_D_CPU0_SB_DQ<27>")
	)
	(segment
		(start 277.687024 -200.849992)
		(end 277.493984 -201.043032)
		(width 0.18288)
		(layer "In11.Cu")
		(net "M_D_CPU0_SB_DQ<27>")
	)
	(segment
		(start 312.248804 -204.63637)
		(end 311.428638 -204.63637)
		(width 0.18288)
		(layer "In11.Cu")
		(net "M_D_CPU0_SB_DQ<27>")
	)
	(segment
		(start 272.034254 -201.122026)
		(end 271.121378 -202.034902)
		(width 0.18288)
		(layer "In11.Cu")
		(net "M_D_CPU0_SB_DQ<27>")
	)
	(segment
		(start 276.827488 -201.043032)
		(end 276.519894 -201.350626)
		(width 0.18288)
		(layer "In11.Cu")
		(net "M_D_CPU0_SB_DQ<27>")
	)
	(segment
		(start 297.344592 -201.144124)
		(end 293.786306 -201.144124)
		(width 0.18288)
		(layer "In11.Cu")
		(net "M_D_CPU0_SB_DQ<27>")
	)
	(segment
		(start 308.422294 -200.944226)
		(end 307.355494 -200.944226)
		(width 0.18288)
		(layer "In11.Cu")
		(net "M_D_CPU0_SB_DQ<27>")
	)
	(segment
		(start 343.892378 -228.786944)
		(end 343.886282 -228.783388)
		(width 0.088646)
		(layer "In11.Cu")
		(net "M_D_CPU0_SB_DQ<27>")
	)
	(segment
		(start 287.716468 -200.447148)
		(end 287.401508 -200.447148)
		(width 0.18288)
		(layer "In11.Cu")
		(net "M_D_CPU0_SB_DQ<27>")
	)
	(segment
		(start 305.903122 -201.076052)
		(end 305.903122 -200.36282)
		(width 0.18288)
		(layer "In11.Cu")
		(net "M_D_CPU0_SB_DQ<27>")
	)
	(segment
		(start 274.849844 -201.157586)
		(end 274.656804 -201.350626)
		(width 0.18288)
		(layer "In11.Cu")
		(net "M_D_CPU0_SB_DQ<27>")
	)
	(segment
		(start 347.784674 -230.650288)
		(end 347.768418 -230.64851)
		(width 0.088646)
		(layer "In11.Cu")
		(net "M_D_CPU0_SB_DQ<27>")
	)
	(segment
		(start 277.493984 -201.043032)
		(end 276.827488 -201.043032)
		(width 0.18288)
		(layer "In11.Cu")
		(net "M_D_CPU0_SB_DQ<27>")
	)
	(segment
		(start 290.610036 -201.157586)
		(end 290.610036 -200.674986)
		(width 0.18288)
		(layer "In11.Cu")
		(net "M_D_CPU0_SB_DQ<27>")
	)
	(segment
		(start 332.32598 -227.07981)
		(end 331.58049 -227.07981)
		(width 0.088646)
		(layer "In11.Cu")
		(net "M_D_CPU0_SB_DQ<27>")
	)
	(segment
		(start 335.428336 -228.783388)
		(end 335.419446 -228.778308)
		(width 0.088646)
		(layer "In11.Cu")
		(net "M_D_CPU0_SB_DQ<27>")
	)
	(segment
		(start 280.710386 -201.143108)
		(end 279.4762 -201.143108)
		(width 0.18288)
		(layer "In11.Cu")
		(net "M_D_CPU0_SB_DQ<27>")
	)
	(segment
		(start 303.817782 -201.269092)
		(end 303.340516 -200.791826)
		(width 0.18288)
		(layer "In11.Cu")
		(net "M_D_CPU0_SB_DQ<27>")
	)
	(segment
		(start 287.909508 -200.928986)
		(end 287.909508 -200.640188)
		(width 0.18288)
		(layer "In11.Cu")
		(net "M_D_CPU0_SB_DQ<27>")
	)
	(arc
		(start 333.548736 -227.155502)
		(mid 333.271923 -227.079632)
		(end 332.993492 -227.149406)
		(width 0.088646)
		(layer "In11.Cu")
		(net "M_D_CPU0_SB_DQ<27>")
	)
	(arc
		(start 335.802732 -228.783388)
		(mid 335.615534 -228.833531)
		(end 335.428336 -228.783388)
		(width 0.088646)
		(layer "In11.Cu")
		(net "M_D_CPU0_SB_DQ<27>")
	)
	(arc
		(start 343.87155 -228.774752)
		(mid 343.595075 -228.707432)
		(end 343.320878 -228.783388)
		(width 0.088646)
		(layer "In11.Cu")
		(net "M_D_CPU0_SB_DQ<27>")
	)
	(arc
		(start 344.817446 -230.40594)
		(mid 344.686532 -230.26958)
		(end 344.638884 -230.086662)
		(width 0.088646)
		(layer "In11.Cu")
		(net "M_D_CPU0_SB_DQ<27>")
	)
	(arc
		(start 334.770984 -227.64496)
		(mid 334.696993 -227.365394)
		(end 334.494378 -227.159058)
		(width 0.088646)
		(layer "In11.Cu")
		(net "M_D_CPU0_SB_DQ<27>")
	)
	(arc
		(start 347.175836 -230.57612)
		(mid 346.893278 -230.651769)
		(end 346.610686 -230.57612)
		(width 0.088646)
		(layer "In11.Cu")
		(net "M_D_CPU0_SB_DQ<27>")
	)
	(arc
		(start 342.946482 -228.783388)
		(mid 342.66378 -228.707612)
		(end 342.381078 -228.783388)
		(width 0.088646)
		(layer "In11.Cu")
		(net "M_D_CPU0_SB_DQ<27>")
	)
	(arc
		(start 344.168984 -229.272846)
		(mid 344.094993 -228.99328)
		(end 343.892378 -228.786944)
		(width 0.088646)
		(layer "In11.Cu")
		(net "M_D_CPU0_SB_DQ<27>")
	)
	(arc
		(start 337.682078 -228.783388)
		(mid 337.49488 -228.833531)
		(end 337.307682 -228.783388)
		(width 0.088646)
		(layer "In11.Cu")
		(net "M_D_CPU0_SB_DQ<27>")
	)
	(arc
		(start 339.561932 -228.783388)
		(mid 339.374734 -228.833531)
		(end 339.187536 -228.783388)
		(width 0.088646)
		(layer "In11.Cu")
		(net "M_D_CPU0_SB_DQ<27>")
	)
	(arc
		(start 340.501478 -228.783388)
		(mid 340.31428 -228.833531)
		(end 340.127082 -228.783388)
		(width 0.088646)
		(layer "In11.Cu")
		(net "M_D_CPU0_SB_DQ<27>")
	)
	(arc
		(start 342.381078 -228.783388)
		(mid 342.19388 -228.833531)
		(end 342.006682 -228.783388)
		(width 0.088646)
		(layer "In11.Cu")
		(net "M_D_CPU0_SB_DQ<27>")
	)
	(arc
		(start 346.236036 -230.57612)
		(mid 345.953334 -230.651896)
		(end 345.670632 -230.57612)
		(width 0.088646)
		(layer "In11.Cu")
		(net "M_D_CPU0_SB_DQ<27>")
	)
	(arc
		(start 348.302834 -230.900478)
		(mid 348.064939 -230.731525)
		(end 347.784674 -230.650288)
		(width 0.088646)
		(layer "In11.Cu")
		(net "M_D_CPU0_SB_DQ<27>")
	)
	(arc
		(start 338.23275 -228.774752)
		(mid 337.956275 -228.707432)
		(end 337.682078 -228.783388)
		(width 0.088646)
		(layer "In11.Cu")
		(net "M_D_CPU0_SB_DQ<27>")
	)
	(arc
		(start 346.610178 -230.57612)
		(mid 346.423124 -230.52607)
		(end 346.236036 -230.57612)
		(width 0.088646)
		(layer "In11.Cu")
		(net "M_D_CPU0_SB_DQ<27>")
	)
	(arc
		(start 343.320878 -228.783388)
		(mid 343.13368 -228.833531)
		(end 342.946482 -228.783388)
		(width 0.088646)
		(layer "In11.Cu")
		(net "M_D_CPU0_SB_DQ<27>")
	)
	(arc
		(start 332.983078 -227.155502)
		(mid 332.79588 -227.205645)
		(end 332.608682 -227.155502)
		(width 0.088646)
		(layer "In11.Cu")
		(net "M_D_CPU0_SB_DQ<27>")
	)
	(arc
		(start 340.116668 -228.777292)
		(mid 339.83849 -228.707569)
		(end 339.561932 -228.783388)
		(width 0.088646)
		(layer "In11.Cu")
		(net "M_D_CPU0_SB_DQ<27>")
	)
	(arc
		(start 341.99195 -228.774752)
		(mid 341.715475 -228.707432)
		(end 341.441278 -228.783388)
		(width 0.088646)
		(layer "In11.Cu")
		(net "M_D_CPU0_SB_DQ<27>")
	)
	(arc
		(start 347.768418 -230.64851)
		(mid 347.663658 -230.626313)
		(end 347.564964 -230.584756)
		(width 0.088646)
		(layer "In11.Cu")
		(net "M_D_CPU0_SB_DQ<27>")
	)
	(arc
		(start 333.923132 -227.155502)
		(mid 333.735934 -227.205645)
		(end 333.548736 -227.155502)
		(width 0.088646)
		(layer "In11.Cu")
		(net "M_D_CPU0_SB_DQ<27>")
	)
	(arc
		(start 344.347546 -229.592124)
		(mid 344.216632 -229.455764)
		(end 344.168984 -229.272846)
		(width 0.088646)
		(layer "In11.Cu")
		(net "M_D_CPU0_SB_DQ<27>")
	)
	(arc
		(start 335.419446 -228.778308)
		(mid 335.288532 -228.641948)
		(end 335.240884 -228.45903)
		(width 0.088646)
		(layer "In11.Cu")
		(net "M_D_CPU0_SB_DQ<27>")
	)
	(arc
		(start 345.200732 -230.41102)
		(mid 345.013534 -230.461163)
		(end 344.826336 -230.41102)
		(width 0.088646)
		(layer "In11.Cu")
		(net "M_D_CPU0_SB_DQ<27>")
	)
	(arc
		(start 336.742278 -228.783388)
		(mid 336.55508 -228.833531)
		(end 336.367882 -228.783388)
		(width 0.088646)
		(layer "In11.Cu")
		(net "M_D_CPU0_SB_DQ<27>")
	)
	(arc
		(start 345.384628 -230.411274)
		(mid 345.29271 -230.38651)
		(end 345.200732 -230.41102)
		(width 0.088646)
		(layer "In11.Cu")
		(net "M_D_CPU0_SB_DQ<27>")
	)
	(arc
		(start 335.240884 -228.45903)
		(mid 335.168711 -228.182362)
		(end 334.970374 -227.97643)
		(width 0.088646)
		(layer "In11.Cu")
		(net "M_D_CPU0_SB_DQ<27>")
	)
	(arc
		(start 344.638884 -230.086662)
		(mid 344.564968 -229.80716)
		(end 344.362532 -229.60076)
		(width 0.088646)
		(layer "In11.Cu")
		(net "M_D_CPU0_SB_DQ<27>")
	)
	(arc
		(start 341.441278 -228.783388)
		(mid 341.25408 -228.833531)
		(end 341.066882 -228.783388)
		(width 0.088646)
		(layer "In11.Cu")
		(net "M_D_CPU0_SB_DQ<27>")
	)
	(arc
		(start 339.177122 -228.777292)
		(mid 338.89869 -228.707446)
		(end 338.621878 -228.783388)
		(width 0.088646)
		(layer "In11.Cu")
		(net "M_D_CPU0_SB_DQ<27>")
	)
	(arc
		(start 336.357468 -228.777292)
		(mid 336.07929 -228.707569)
		(end 335.802732 -228.783388)
		(width 0.088646)
		(layer "In11.Cu")
		(net "M_D_CPU0_SB_DQ<27>")
	)
	(arc
		(start 337.29295 -228.774752)
		(mid 337.016475 -228.707432)
		(end 336.742278 -228.783388)
		(width 0.088646)
		(layer "In11.Cu")
		(net "M_D_CPU0_SB_DQ<27>")
	)
	(arc
		(start 338.621878 -228.783388)
		(mid 338.43468 -228.833531)
		(end 338.247482 -228.783388)
		(width 0.088646)
		(layer "In11.Cu")
		(net "M_D_CPU0_SB_DQ<27>")
	)
	(arc
		(start 334.958182 -227.969318)
		(mid 334.823249 -227.835964)
		(end 334.770984 -227.653596)
		(width 0.088646)
		(layer "In11.Cu")
		(net "M_D_CPU0_SB_DQ<27>")
	)
	(arc
		(start 341.05215 -228.774752)
		(mid 340.775675 -228.707432)
		(end 340.501478 -228.783388)
		(width 0.088646)
		(layer "In11.Cu")
		(net "M_D_CPU0_SB_DQ<27>")
	)
	(arc
		(start 332.608682 -227.155502)
		(mid 332.472313 -227.09906)
		(end 332.32598 -227.07981)
		(width 0.088646)
		(layer "In11.Cu")
		(net "M_D_CPU0_SB_DQ<27>")
	)
	(arc
		(start 347.550232 -230.57612)
		(mid 347.363034 -230.525977)
		(end 347.175836 -230.57612)
		(width 0.088646)
		(layer "In11.Cu")
		(net "M_D_CPU0_SB_DQ<27>")
	)
	(arc
		(start 334.477868 -227.149406)
		(mid 334.19969 -227.079683)
		(end 333.923132 -227.155502)
		(width 0.088646)
		(layer "In11.Cu")
		(net "M_D_CPU0_SB_DQ<27>")
	)
	(segment
		(start 347.832934 -232.250488)
		(end 347.83268 -232.250234)
		(width 0.20066)
		(layer "F.Cu")
		(net "M_D_CPU0_SB_DQ<26>")
	)
	(segment
		(start 265.601958 -203.311252)
		(end 265.601958 -202.985624)
		(width 0.20066)
		(layer "F.Cu")
		(net "M_D_CPU0_SB_DQ<26>")
	)
	(segment
		(start 267.724382 -203.266802)
		(end 266.409678 -203.266802)
		(width 0.20066)
		(layer "F.Cu")
		(net "M_D_CPU0_SB_DQ<26>")
	)
	(segment
		(start 264.825226 -202.84186)
		(end 262.765286 -202.84186)
		(width 0.1016)
		(layer "F.Cu")
		(net "M_D_CPU0_SB_DQ<26>")
	)
	(segment
		(start 347.83268 -232.250234)
		(end 347.83268 -231.714548)
		(width 0.20066)
		(layer "F.Cu")
		(net "M_D_CPU0_SB_DQ<26>")
	)
	(segment
		(start 265.769344 -203.478638)
		(end 265.601958 -203.311252)
		(width 0.20066)
		(layer "F.Cu")
		(net "M_D_CPU0_SB_DQ<26>")
	)
	(segment
		(start 262.50011 -202.8317)
		(end 261.762748 -202.8317)
		(width 0.20066)
		(layer "F.Cu")
		(net "M_D_CPU0_SB_DQ<26>")
	)
	(segment
		(start 261.327646 -203.266802)
		(end 260.180582 -203.266802)
		(width 0.20066)
		(layer "F.Cu")
		(net "M_D_CPU0_SB_DQ<26>")
	)
	(segment
		(start 265.458194 -202.84186)
		(end 264.825226 -202.84186)
		(width 0.20066)
		(layer "F.Cu")
		(net "M_D_CPU0_SB_DQ<26>")
	)
	(segment
		(start 266.197842 -203.478638)
		(end 265.769344 -203.478638)
		(width 0.20066)
		(layer "F.Cu")
		(net "M_D_CPU0_SB_DQ<26>")
	)
	(segment
		(start 262.51027 -202.84186)
		(end 262.50011 -202.8317)
		(width 0.101854)
		(layer "F.Cu")
		(net "M_D_CPU0_SB_DQ<26>")
	)
	(segment
		(start 261.762748 -202.8317)
		(end 261.327646 -203.266802)
		(width 0.20066)
		(layer "F.Cu")
		(net "M_D_CPU0_SB_DQ<26>")
	)
	(segment
		(start 262.765286 -202.84186)
		(end 262.51027 -202.84186)
		(width 0.101854)
		(layer "F.Cu")
		(net "M_D_CPU0_SB_DQ<26>")
	)
	(segment
		(start 268.829282 -203.266802)
		(end 267.724382 -203.266802)
		(width 0.20066)
		(layer "F.Cu")
		(net "M_D_CPU0_SB_DQ<26>")
	)
	(segment
		(start 266.409678 -203.266802)
		(end 266.197842 -203.478638)
		(width 0.20066)
		(layer "F.Cu")
		(net "M_D_CPU0_SB_DQ<26>")
	)
	(segment
		(start 265.601958 -202.985624)
		(end 265.458194 -202.84186)
		(width 0.20066)
		(layer "F.Cu")
		(net "M_D_CPU0_SB_DQ<26>")
	)
	(segment
		(start 314.994798 -208.916524)
		(end 314.384944 -208.916524)
		(width 0.18288)
		(layer "In11.Cu")
		(net "M_D_CPU0_SB_DQ<26>")
	)
	(segment
		(start 288.94659 -203.455016)
		(end 288.94659 -203.118466)
		(width 0.18288)
		(layer "In11.Cu")
		(net "M_D_CPU0_SB_DQ<26>")
	)
	(segment
		(start 320.426334 -214.34806)
		(end 314.994798 -208.916524)
		(width 0.18288)
		(layer "In11.Cu")
		(net "M_D_CPU0_SB_DQ<26>")
	)
	(segment
		(start 289.64763 -203.118466)
		(end 289.64763 -203.455016)
		(width 0.18288)
		(layer "In11.Cu")
		(net "M_D_CPU0_SB_DQ<26>")
	)
	(segment
		(start 311.495694 -206.456026)
		(end 310.617616 -205.577948)
		(width 0.18288)
		(layer "In11.Cu")
		(net "M_D_CPU0_SB_DQ<26>")
	)
	(segment
		(start 346.154502 -232.030778)
		(end 346.140278 -232.038906)
		(width 0.088646)
		(layer "In11.Cu")
		(net "M_D_CPU0_SB_DQ<26>")
	)
	(segment
		(start 293.792656 -202.842368)
		(end 293.657782 -202.707494)
		(width 0.18288)
		(layer "In11.Cu")
		(net "M_D_CPU0_SB_DQ<26>")
	)
	(segment
		(start 314.384944 -208.916524)
		(end 312.920126 -207.451706)
		(width 0.18288)
		(layer "In11.Cu")
		(net "M_D_CPU0_SB_DQ<26>")
	)
	(segment
		(start 300.897798 -203.693522)
		(end 298.11599 -203.693522)
		(width 0.18288)
		(layer "In11.Cu")
		(net "M_D_CPU0_SB_DQ<26>")
	)
	(segment
		(start 271.324832 -203.222098)
		(end 271.009872 -203.222098)
		(width 0.18288)
		(layer "In11.Cu")
		(net "M_D_CPU0_SB_DQ<26>")
	)
	(segment
		(start 303.360582 -202.742292)
		(end 301.849028 -202.742292)
		(width 0.18288)
		(layer "In11.Cu")
		(net "M_D_CPU0_SB_DQ<26>")
	)
	(segment
		(start 290.15563 -202.925426)
		(end 289.84067 -202.925426)
		(width 0.18288)
		(layer "In11.Cu")
		(net "M_D_CPU0_SB_DQ<26>")
	)
	(segment
		(start 290.85667 -203.648056)
		(end 290.54171 -203.648056)
		(width 0.18288)
		(layer "In11.Cu")
		(net "M_D_CPU0_SB_DQ<26>")
	)
	(segment
		(start 270.816832 -203.415138)
		(end 270.816832 -203.566776)
		(width 0.18288)
		(layer "In11.Cu")
		(net "M_D_CPU0_SB_DQ<26>")
	)
	(segment
		(start 344.826082 -232.038906)
		(end 344.817192 -232.033826)
		(width 0.088646)
		(layer "In11.Cu")
		(net "M_D_CPU0_SB_DQ<26>")
	)
	(segment
		(start 329.978004 -226.774248)
		(end 329.976226 -226.776026)
		(width 0.18288)
		(layer "In11.Cu")
		(net "M_D_CPU0_SB_DQ<26>")
	)
	(segment
		(start 291.24275 -202.925426)
		(end 291.04971 -203.118466)
		(width 0.18288)
		(layer "In11.Cu")
		(net "M_D_CPU0_SB_DQ<26>")
	)
	(segment
		(start 283.154374 -203.692506)
		(end 282.316428 -202.85456)
		(width 0.18288)
		(layer "In11.Cu")
		(net "M_D_CPU0_SB_DQ<26>")
	)
	(segment
		(start 296.226484 -203.052426)
		(end 296.016426 -202.842368)
		(width 0.18288)
		(layer "In11.Cu")
		(net "M_D_CPU0_SB_DQ<26>")
	)
	(segment
		(start 289.64763 -203.455016)
		(end 289.45459 -203.648056)
		(width 0.18288)
		(layer "In11.Cu")
		(net "M_D_CPU0_SB_DQ<26>")
	)
	(segment
		(start 278.133048 -202.882246)
		(end 277.973028 -202.722226)
		(width 0.18288)
		(layer "In11.Cu")
		(net "M_D_CPU0_SB_DQ<26>")
	)
	(segment
		(start 290.34867 -203.455016)
		(end 290.34867 -203.118466)
		(width 0.18288)
		(layer "In11.Cu")
		(net "M_D_CPU0_SB_DQ<26>")
	)
	(segment
		(start 310.617616 -205.577948)
		(end 308.608984 -205.577948)
		(width 0.18288)
		(layer "In11.Cu")
		(net "M_D_CPU0_SB_DQ<26>")
	)
	(segment
		(start 336.287364 -229.588568)
		(end 336.272632 -229.597204)
		(width 0.088646)
		(layer "In11.Cu")
		(net "M_D_CPU0_SB_DQ<26>")
	)
	(segment
		(start 344.356436 -231.224836)
		(end 344.347546 -231.219756)
		(width 0.088646)
		(layer "In11.Cu")
		(net "M_D_CPU0_SB_DQ<26>")
	)
	(segment
		(start 272.815304 -203.759816)
		(end 271.710912 -203.759816)
		(width 0.18288)
		(layer "In11.Cu")
		(net "M_D_CPU0_SB_DQ<26>")
	)
	(segment
		(start 331.807058 -228.020372)
		(end 330.560934 -226.774248)
		(width 0.088646)
		(layer "In11.Cu")
		(net "M_D_CPU0_SB_DQ<26>")
	)
	(segment
		(start 305.844702 -203.021692)
		(end 305.651662 -202.828652)
		(width 0.18288)
		(layer "In11.Cu")
		(net "M_D_CPU0_SB_DQ<26>")
	)
	(segment
		(start 307.691282 -204.040486)
		(end 306.672488 -203.021692)
		(width 0.18288)
		(layer "In11.Cu")
		(net "M_D_CPU0_SB_DQ<26>")
	)
	(segment
		(start 282.316428 -202.85456)
		(end 281.434032 -202.85456)
		(width 0.18288)
		(layer "In11.Cu")
		(net "M_D_CPU0_SB_DQ<26>")
	)
	(segment
		(start 334.301084 -228.45903)
		(end 334.301084 -228.440488)
		(width 0.088646)
		(layer "In11.Cu")
		(net "M_D_CPU0_SB_DQ<26>")
	)
	(segment
		(start 329.976226 -226.776026)
		(end 320.426334 -217.226134)
		(width 0.18288)
		(layer "In11.Cu")
		(net "M_D_CPU0_SB_DQ<26>")
	)
	(segment
		(start 280.405586 -202.8444)
		(end 279.497282 -202.8444)
		(width 0.18288)
		(layer "In11.Cu")
		(net "M_D_CPU0_SB_DQ<26>")
	)
	(segment
		(start 298.11599 -203.693522)
		(end 297.474894 -203.052426)
		(width 0.18288)
		(layer "In11.Cu")
		(net "M_D_CPU0_SB_DQ<26>")
	)
	(segment
		(start 276.672294 -203.103226)
		(end 273.471894 -203.103226)
		(width 0.18288)
		(layer "In11.Cu")
		(net "M_D_CPU0_SB_DQ<26>")
	)
	(segment
		(start 330.560934 -226.774248)
		(end 330.313538 -226.774248)
		(width 0.088646)
		(layer "In11.Cu")
		(net "M_D_CPU0_SB_DQ<26>")
	)
	(segment
		(start 339.106764 -229.588568)
		(end 339.092032 -229.597204)
		(width 0.088646)
		(layer "In11.Cu")
		(net "M_D_CPU0_SB_DQ<26>")
	)
	(segment
		(start 334.018636 -227.969318)
		(end 334.008222 -227.963222)
		(width 0.088646)
		(layer "In11.Cu")
		(net "M_D_CPU0_SB_DQ<26>")
	)
	(segment
		(start 291.04971 -203.118466)
		(end 291.04971 -203.455016)
		(width 0.18288)
		(layer "In11.Cu")
		(net "M_D_CPU0_SB_DQ<26>")
	)
	(segment
		(start 278.994108 -202.722226)
		(end 278.834088 -202.882246)
		(width 0.18288)
		(layer "In11.Cu")
		(net "M_D_CPU0_SB_DQ<26>")
	)
	(segment
		(start 340.986364 -229.588568)
		(end 340.971632 -229.597204)
		(width 0.088646)
		(layer "In11.Cu")
		(net "M_D_CPU0_SB_DQ<26>")
	)
	(segment
		(start 288.294064 -202.646026)
		(end 286.883094 -202.646026)
		(width 0.18288)
		(layer "In11.Cu")
		(net "M_D_CPU0_SB_DQ<26>")
	)
	(segment
		(start 345.765882 -232.038906)
		(end 345.75115 -232.03027)
		(width 0.088646)
		(layer "In11.Cu")
		(net "M_D_CPU0_SB_DQ<26>")
	)
	(segment
		(start 304.950622 -202.626722)
		(end 304.950622 -202.828652)
		(width 0.18288)
		(layer "In11.Cu")
		(net "M_D_CPU0_SB_DQ<26>")
	)
	(segment
		(start 291.963094 -202.925426)
		(end 291.24275 -202.925426)
		(width 0.18288)
		(layer "In11.Cu")
		(net "M_D_CPU0_SB_DQ<26>")
	)
	(segment
		(start 301.849028 -202.742292)
		(end 300.897798 -203.693522)
		(width 0.18288)
		(layer "In11.Cu")
		(net "M_D_CPU0_SB_DQ<26>")
	)
	(segment
		(start 277.973028 -202.722226)
		(end 277.053294 -202.722226)
		(width 0.18288)
		(layer "In11.Cu")
		(net "M_D_CPU0_SB_DQ<26>")
	)
	(segment
		(start 343.892378 -230.414576)
		(end 343.886282 -230.41102)
		(width 0.088646)
		(layer "In11.Cu")
		(net "M_D_CPU0_SB_DQ<26>")
	)
	(segment
		(start 306.672488 -203.021692)
		(end 305.844702 -203.021692)
		(width 0.18288)
		(layer "In11.Cu")
		(net "M_D_CPU0_SB_DQ<26>")
	)
	(segment
		(start 308.999636 -204.859636)
		(end 309.159656 -204.699616)
		(width 0.18288)
		(layer "In11.Cu")
		(net "M_D_CPU0_SB_DQ<26>")
	)
	(segment
		(start 289.45459 -203.648056)
		(end 289.13963 -203.648056)
		(width 0.18288)
		(layer "In11.Cu")
		(net "M_D_CPU0_SB_DQ<26>")
	)
	(segment
		(start 305.651662 -202.828652)
		(end 305.651662 -202.626722)
		(width 0.18288)
		(layer "In11.Cu")
		(net "M_D_CPU0_SB_DQ<26>")
	)
	(segment
		(start 278.133048 -203.256134)
		(end 278.133048 -202.882246)
		(width 0.18288)
		(layer "In11.Cu")
		(net "M_D_CPU0_SB_DQ<26>")
	)
	(segment
		(start 341.921846 -229.591108)
		(end 341.911432 -229.597204)
		(width 0.088646)
		(layer "In11.Cu")
		(net "M_D_CPU0_SB_DQ<26>")
	)
	(segment
		(start 281.434032 -202.85456)
		(end 281.116786 -203.171806)
		(width 0.18288)
		(layer "In11.Cu")
		(net "M_D_CPU0_SB_DQ<26>")
	)
	(segment
		(start 305.143662 -202.433682)
		(end 304.950622 -202.626722)
		(width 0.18288)
		(layer "In11.Cu")
		(net "M_D_CPU0_SB_DQ<26>")
	)
	(segment
		(start 303.639982 -203.021692)
		(end 303.360582 -202.742292)
		(width 0.18288)
		(layer "In11.Cu")
		(net "M_D_CPU0_SB_DQ<26>")
	)
	(segment
		(start 290.54171 -203.648056)
		(end 290.34867 -203.455016)
		(width 0.18288)
		(layer "In11.Cu")
		(net "M_D_CPU0_SB_DQ<26>")
	)
	(segment
		(start 292.181026 -202.707494)
		(end 291.963094 -202.925426)
		(width 0.18288)
		(layer "In11.Cu")
		(net "M_D_CPU0_SB_DQ<26>")
	)
	(segment
		(start 278.834088 -203.289154)
		(end 278.674068 -203.449174)
		(width 0.18288)
		(layer "In11.Cu")
		(net "M_D_CPU0_SB_DQ<26>")
	)
	(segment
		(start 334.488536 -228.783388)
		(end 334.479646 -228.778308)
		(width 0.088646)
		(layer "In11.Cu")
		(net "M_D_CPU0_SB_DQ<26>")
	)
	(segment
		(start 278.674068 -203.449174)
		(end 278.326088 -203.449174)
		(width 0.18288)
		(layer "In11.Cu")
		(net "M_D_CPU0_SB_DQ<26>")
	)
	(segment
		(start 297.474894 -203.052426)
		(end 296.226484 -203.052426)
		(width 0.18288)
		(layer "In11.Cu")
		(net "M_D_CPU0_SB_DQ<26>")
	)
	(segment
		(start 277.053294 -202.722226)
		(end 276.672294 -203.103226)
		(width 0.18288)
		(layer "In11.Cu")
		(net "M_D_CPU0_SB_DQ<26>")
	)
	(segment
		(start 280.732992 -203.171806)
		(end 280.405586 -202.8444)
		(width 0.18288)
		(layer "In11.Cu")
		(net "M_D_CPU0_SB_DQ<26>")
	)
	(segment
		(start 305.458622 -202.433682)
		(end 305.143662 -202.433682)
		(width 0.18288)
		(layer "In11.Cu")
		(net "M_D_CPU0_SB_DQ<26>")
	)
	(segment
		(start 343.69883 -230.086662)
		(end 343.69883 -230.071168)
		(width 0.088646)
		(layer "In11.Cu")
		(net "M_D_CPU0_SB_DQ<26>")
	)
	(segment
		(start 308.450234 -205.419198)
		(end 308.450234 -204.99705)
		(width 0.18288)
		(layer "In11.Cu")
		(net "M_D_CPU0_SB_DQ<26>")
	)
	(segment
		(start 330.313538 -226.774248)
		(end 329.978004 -226.774248)
		(width 0.18288)
		(layer "In11.Cu")
		(net "M_D_CPU0_SB_DQ<26>")
	)
	(segment
		(start 320.426334 -217.226134)
		(end 320.426334 -214.34806)
		(width 0.18288)
		(layer "In11.Cu")
		(net "M_D_CPU0_SB_DQ<26>")
	)
	(segment
		(start 288.94659 -203.118466)
		(end 288.75355 -202.925426)
		(width 0.18288)
		(layer "In11.Cu")
		(net "M_D_CPU0_SB_DQ<26>")
	)
	(segment
		(start 304.757582 -203.021692)
		(end 303.639982 -203.021692)
		(width 0.18288)
		(layer "In11.Cu")
		(net "M_D_CPU0_SB_DQ<26>")
	)
	(segment
		(start 344.63863 -231.714548)
		(end 344.63863 -231.69245)
		(width 0.088646)
		(layer "In11.Cu")
		(net "M_D_CPU0_SB_DQ<26>")
	)
	(segment
		(start 309.159656 -204.200506)
		(end 308.999636 -204.040486)
		(width 0.18288)
		(layer "In11.Cu")
		(net "M_D_CPU0_SB_DQ<26>")
	)
	(segment
		(start 270.816832 -203.566776)
		(end 270.623792 -203.759816)
		(width 0.18288)
		(layer "In11.Cu")
		(net "M_D_CPU0_SB_DQ<26>")
	)
	(segment
		(start 284.698694 -203.692506)
		(end 283.154374 -203.692506)
		(width 0.18288)
		(layer "In11.Cu")
		(net "M_D_CPU0_SB_DQ<26>")
	)
	(segment
		(start 289.84067 -202.925426)
		(end 289.64763 -203.118466)
		(width 0.18288)
		(layer "In11.Cu")
		(net "M_D_CPU0_SB_DQ<26>")
	)
	(segment
		(start 343.886282 -230.41102)
		(end 343.877392 -230.40594)
		(width 0.088646)
		(layer "In11.Cu")
		(net "M_D_CPU0_SB_DQ<26>")
	)
	(segment
		(start 304.950622 -202.828652)
		(end 304.757582 -203.021692)
		(width 0.18288)
		(layer "In11.Cu")
		(net "M_D_CPU0_SB_DQ<26>")
	)
	(segment
		(start 286.883094 -202.646026)
		(end 285.685738 -203.843382)
		(width 0.18288)
		(layer "In11.Cu")
		(net "M_D_CPU0_SB_DQ<26>")
	)
	(segment
		(start 289.13963 -203.648056)
		(end 288.94659 -203.455016)
		(width 0.18288)
		(layer "In11.Cu")
		(net "M_D_CPU0_SB_DQ<26>")
	)
	(segment
		(start 284.84957 -203.843382)
		(end 284.698694 -203.692506)
		(width 0.18288)
		(layer "In11.Cu")
		(net "M_D_CPU0_SB_DQ<26>")
	)
	(segment
		(start 312.275474 -206.456026)
		(end 311.495694 -206.456026)
		(width 0.18288)
		(layer "In11.Cu")
		(net "M_D_CPU0_SB_DQ<26>")
	)
	(segment
		(start 312.920126 -207.451706)
		(end 312.920126 -207.100678)
		(width 0.18288)
		(layer "In11.Cu")
		(net "M_D_CPU0_SB_DQ<26>")
	)
	(segment
		(start 305.651662 -202.626722)
		(end 305.458622 -202.433682)
		(width 0.18288)
		(layer "In11.Cu")
		(net "M_D_CPU0_SB_DQ<26>")
	)
	(segment
		(start 290.34867 -203.118466)
		(end 290.15563 -202.925426)
		(width 0.18288)
		(layer "In11.Cu")
		(net "M_D_CPU0_SB_DQ<26>")
	)
	(segment
		(start 293.657782 -202.707494)
		(end 292.181026 -202.707494)
		(width 0.18288)
		(layer "In11.Cu")
		(net "M_D_CPU0_SB_DQ<26>")
	)
	(segment
		(start 335.898236 -229.597204)
		(end 335.887822 -229.591108)
		(width 0.088646)
		(layer "In11.Cu")
		(net "M_D_CPU0_SB_DQ<26>")
	)
	(segment
		(start 279.497282 -202.8444)
		(end 279.375108 -202.722226)
		(width 0.18288)
		(layer "In11.Cu")
		(net "M_D_CPU0_SB_DQ<26>")
	)
	(segment
		(start 337.227164 -229.588568)
		(end 337.212432 -229.597204)
		(width 0.088646)
		(layer "In11.Cu")
		(net "M_D_CPU0_SB_DQ<26>")
	)
	(segment
		(start 271.009872 -203.222098)
		(end 270.816832 -203.415138)
		(width 0.18288)
		(layer "In11.Cu")
		(net "M_D_CPU0_SB_DQ<26>")
	)
	(segment
		(start 271.517872 -203.415138)
		(end 271.324832 -203.222098)
		(width 0.18288)
		(layer "In11.Cu")
		(net "M_D_CPU0_SB_DQ<26>")
	)
	(segment
		(start 308.608984 -205.577948)
		(end 308.450234 -205.419198)
		(width 0.18288)
		(layer "In11.Cu")
		(net "M_D_CPU0_SB_DQ<26>")
	)
	(segment
		(start 340.046564 -229.588568)
		(end 340.031832 -229.597204)
		(width 0.088646)
		(layer "In11.Cu")
		(net "M_D_CPU0_SB_DQ<26>")
	)
	(segment
		(start 288.573464 -202.925426)
		(end 288.294064 -202.646026)
		(width 0.18288)
		(layer "In11.Cu")
		(net "M_D_CPU0_SB_DQ<26>")
	)
	(segment
		(start 308.999636 -204.040486)
		(end 307.691282 -204.040486)
		(width 0.18288)
		(layer "In11.Cu")
		(net "M_D_CPU0_SB_DQ<26>")
	)
	(segment
		(start 278.834088 -202.882246)
		(end 278.834088 -203.289154)
		(width 0.18288)
		(layer "In11.Cu")
		(net "M_D_CPU0_SB_DQ<26>")
	)
	(segment
		(start 332.32598 -228.020372)
		(end 331.807058 -228.020372)
		(width 0.088646)
		(layer "In11.Cu")
		(net "M_D_CPU0_SB_DQ<26>")
	)
	(segment
		(start 291.04971 -203.455016)
		(end 290.85667 -203.648056)
		(width 0.18288)
		(layer "In11.Cu")
		(net "M_D_CPU0_SB_DQ<26>")
	)
	(segment
		(start 308.450234 -204.99705)
		(end 308.587648 -204.859636)
		(width 0.18288)
		(layer "In11.Cu")
		(net "M_D_CPU0_SB_DQ<26>")
	)
	(segment
		(start 281.116786 -203.171806)
		(end 280.732992 -203.171806)
		(width 0.18288)
		(layer "In11.Cu")
		(net "M_D_CPU0_SB_DQ<26>")
	)
	(segment
		(start 312.920126 -207.100678)
		(end 312.275474 -206.456026)
		(width 0.18288)
		(layer "In11.Cu")
		(net "M_D_CPU0_SB_DQ<26>")
	)
	(segment
		(start 271.517872 -203.566776)
		(end 271.517872 -203.415138)
		(width 0.18288)
		(layer "In11.Cu")
		(net "M_D_CPU0_SB_DQ<26>")
	)
	(segment
		(start 296.016426 -202.842368)
		(end 293.792656 -202.842368)
		(width 0.18288)
		(layer "In11.Cu")
		(net "M_D_CPU0_SB_DQ<26>")
	)
	(segment
		(start 279.375108 -202.722226)
		(end 278.994108 -202.722226)
		(width 0.18288)
		(layer "In11.Cu")
		(net "M_D_CPU0_SB_DQ<26>")
	)
	(segment
		(start 308.587648 -204.859636)
		(end 308.999636 -204.859636)
		(width 0.18288)
		(layer "In11.Cu")
		(net "M_D_CPU0_SB_DQ<26>")
	)
	(segment
		(start 273.471894 -203.103226)
		(end 272.815304 -203.759816)
		(width 0.18288)
		(layer "In11.Cu")
		(net "M_D_CPU0_SB_DQ<26>")
	)
	(segment
		(start 278.326088 -203.449174)
		(end 278.133048 -203.256134)
		(width 0.18288)
		(layer "In11.Cu")
		(net "M_D_CPU0_SB_DQ<26>")
	)
	(segment
		(start 309.159656 -204.699616)
		(end 309.159656 -204.200506)
		(width 0.18288)
		(layer "In11.Cu")
		(net "M_D_CPU0_SB_DQ<26>")
	)
	(segment
		(start 333.078582 -227.969318)
		(end 333.06385 -227.960682)
		(width 0.088646)
		(layer "In11.Cu")
		(net "M_D_CPU0_SB_DQ<26>")
	)
	(segment
		(start 334.770984 -229.281482)
		(end 334.770984 -229.26294)
		(width 0.088646)
		(layer "In11.Cu")
		(net "M_D_CPU0_SB_DQ<26>")
	)
	(segment
		(start 271.710912 -203.759816)
		(end 271.517872 -203.566776)
		(width 0.18288)
		(layer "In11.Cu")
		(net "M_D_CPU0_SB_DQ<26>")
	)
	(segment
		(start 269.322296 -203.759816)
		(end 268.829282 -203.266802)
		(width 0.18288)
		(layer "In11.Cu")
		(net "M_D_CPU0_SB_DQ<26>")
	)
	(segment
		(start 288.75355 -202.925426)
		(end 288.573464 -202.925426)
		(width 0.18288)
		(layer "In11.Cu")
		(net "M_D_CPU0_SB_DQ<26>")
	)
	(segment
		(start 285.685738 -203.843382)
		(end 284.84957 -203.843382)
		(width 0.18288)
		(layer "In11.Cu")
		(net "M_D_CPU0_SB_DQ<26>")
	)
	(segment
		(start 342.861392 -229.591108)
		(end 342.850978 -229.597204)
		(width 0.088646)
		(layer "In11.Cu")
		(net "M_D_CPU0_SB_DQ<26>")
	)
	(segment
		(start 270.623792 -203.759816)
		(end 269.322296 -203.759816)
		(width 0.18288)
		(layer "In11.Cu")
		(net "M_D_CPU0_SB_DQ<26>")
	)
	(arc
		(start 334.770984 -229.26294)
		(mid 334.692873 -228.985991)
		(end 334.488536 -228.783388)
		(width 0.088646)
		(layer "In11.Cu")
		(net "M_D_CPU0_SB_DQ<26>")
	)
	(arc
		(start 344.168984 -230.900478)
		(mid 344.094993 -230.620912)
		(end 343.892378 -230.414576)
		(width 0.088646)
		(layer "In11.Cu")
		(net "M_D_CPU0_SB_DQ<26>")
	)
	(arc
		(start 334.958182 -229.597204)
		(mid 334.823249 -229.46385)
		(end 334.770984 -229.281482)
		(width 0.088646)
		(layer "In11.Cu")
		(net "M_D_CPU0_SB_DQ<26>")
	)
	(arc
		(start 342.850978 -229.597204)
		(mid 342.66378 -229.647347)
		(end 342.476582 -229.597204)
		(width 0.088646)
		(layer "In11.Cu")
		(net "M_D_CPU0_SB_DQ<26>")
	)
	(arc
		(start 340.031832 -229.597204)
		(mid 339.844634 -229.647347)
		(end 339.657436 -229.597204)
		(width 0.088646)
		(layer "In11.Cu")
		(net "M_D_CPU0_SB_DQ<26>")
	)
	(arc
		(start 336.838036 -229.597204)
		(mid 336.563837 -229.521369)
		(end 336.287364 -229.588568)
		(width 0.088646)
		(layer "In11.Cu")
		(net "M_D_CPU0_SB_DQ<26>")
	)
	(arc
		(start 346.319348 -231.85628)
		(mid 346.249686 -231.955579)
		(end 346.154502 -232.030778)
		(width 0.088646)
		(layer "In11.Cu")
		(net "M_D_CPU0_SB_DQ<26>")
	)
	(arc
		(start 337.212432 -229.597204)
		(mid 337.025234 -229.647347)
		(end 336.838036 -229.597204)
		(width 0.088646)
		(layer "In11.Cu")
		(net "M_D_CPU0_SB_DQ<26>")
	)
	(arc
		(start 345.200478 -232.038906)
		(mid 345.01328 -232.089049)
		(end 344.826082 -232.038906)
		(width 0.088646)
		(layer "In11.Cu")
		(net "M_D_CPU0_SB_DQ<26>")
	)
	(arc
		(start 334.479646 -228.778308)
		(mid 334.348732 -228.641948)
		(end 334.301084 -228.45903)
		(width 0.088646)
		(layer "In11.Cu")
		(net "M_D_CPU0_SB_DQ<26>")
	)
	(arc
		(start 333.06385 -227.960682)
		(mid 332.787409 -227.893516)
		(end 332.513178 -227.969318)
		(width 0.088646)
		(layer "In11.Cu")
		(net "M_D_CPU0_SB_DQ<26>")
	)
	(arc
		(start 335.332578 -229.597204)
		(mid 335.14538 -229.647347)
		(end 334.958182 -229.597204)
		(width 0.088646)
		(layer "In11.Cu")
		(net "M_D_CPU0_SB_DQ<26>")
	)
	(arc
		(start 343.416636 -229.597204)
		(mid 343.139823 -229.521334)
		(end 342.861392 -229.591108)
		(width 0.088646)
		(layer "In11.Cu")
		(net "M_D_CPU0_SB_DQ<26>")
	)
	(arc
		(start 342.476582 -229.597204)
		(mid 342.200023 -229.521461)
		(end 341.921846 -229.591108)
		(width 0.088646)
		(layer "In11.Cu")
		(net "M_D_CPU0_SB_DQ<26>")
	)
	(arc
		(start 337.777836 -229.597204)
		(mid 337.503637 -229.521369)
		(end 337.227164 -229.588568)
		(width 0.088646)
		(layer "In11.Cu")
		(net "M_D_CPU0_SB_DQ<26>")
	)
	(arc
		(start 340.971632 -229.597204)
		(mid 340.784434 -229.647347)
		(end 340.597236 -229.597204)
		(width 0.088646)
		(layer "In11.Cu")
		(net "M_D_CPU0_SB_DQ<26>")
	)
	(arc
		(start 333.452978 -227.969318)
		(mid 333.26578 -228.019461)
		(end 333.078582 -227.969318)
		(width 0.088646)
		(layer "In11.Cu")
		(net "M_D_CPU0_SB_DQ<26>")
	)
	(arc
		(start 344.817192 -232.033826)
		(mid 344.686278 -231.897466)
		(end 344.63863 -231.714548)
		(width 0.088646)
		(layer "In11.Cu")
		(net "M_D_CPU0_SB_DQ<26>")
	)
	(arc
		(start 341.537036 -229.597204)
		(mid 341.262837 -229.521369)
		(end 340.986364 -229.588568)
		(width 0.088646)
		(layer "In11.Cu")
		(net "M_D_CPU0_SB_DQ<26>")
	)
	(arc
		(start 345.75115 -232.03027)
		(mid 345.474675 -231.96295)
		(end 345.200478 -232.038906)
		(width 0.088646)
		(layer "In11.Cu")
		(net "M_D_CPU0_SB_DQ<26>")
	)
	(arc
		(start 343.69883 -230.071168)
		(mid 343.61946 -229.797434)
		(end 343.416636 -229.597204)
		(width 0.088646)
		(layer "In11.Cu")
		(net "M_D_CPU0_SB_DQ<26>")
	)
	(arc
		(start 343.877392 -230.40594)
		(mid 343.746478 -230.26958)
		(end 343.69883 -230.086662)
		(width 0.088646)
		(layer "In11.Cu")
		(net "M_D_CPU0_SB_DQ<26>")
	)
	(arc
		(start 334.008222 -227.963222)
		(mid 333.72979 -227.893408)
		(end 333.452978 -227.969318)
		(width 0.088646)
		(layer "In11.Cu")
		(net "M_D_CPU0_SB_DQ<26>")
	)
	(arc
		(start 347.081094 -231.322626)
		(mid 346.837014 -231.303852)
		(end 346.623894 -231.424226)
		(width 0.088646)
		(layer "In11.Cu")
		(net "M_D_CPU0_SB_DQ<26>")
	)
	(arc
		(start 339.092032 -229.597204)
		(mid 338.904834 -229.647347)
		(end 338.717636 -229.597204)
		(width 0.088646)
		(layer "In11.Cu")
		(net "M_D_CPU0_SB_DQ<26>")
	)
	(arc
		(start 338.717636 -229.597204)
		(mid 338.434934 -229.521428)
		(end 338.152232 -229.597204)
		(width 0.088646)
		(layer "In11.Cu")
		(net "M_D_CPU0_SB_DQ<26>")
	)
	(arc
		(start 347.83268 -231.714548)
		(mid 347.467544 -231.498151)
		(end 347.081094 -231.322626)
		(width 0.088646)
		(layer "In11.Cu")
		(net "M_D_CPU0_SB_DQ<26>")
	)
	(arc
		(start 344.347546 -231.219756)
		(mid 344.216632 -231.083396)
		(end 344.168984 -230.900478)
		(width 0.088646)
		(layer "In11.Cu")
		(net "M_D_CPU0_SB_DQ<26>")
	)
	(arc
		(start 344.63863 -231.69245)
		(mid 344.557719 -231.422322)
		(end 344.356436 -231.224836)
		(width 0.088646)
		(layer "In11.Cu")
		(net "M_D_CPU0_SB_DQ<26>")
	)
	(arc
		(start 338.152232 -229.597204)
		(mid 337.965034 -229.647347)
		(end 337.777836 -229.597204)
		(width 0.088646)
		(layer "In11.Cu")
		(net "M_D_CPU0_SB_DQ<26>")
	)
	(arc
		(start 336.272632 -229.597204)
		(mid 336.085434 -229.647347)
		(end 335.898236 -229.597204)
		(width 0.088646)
		(layer "In11.Cu")
		(net "M_D_CPU0_SB_DQ<26>")
	)
	(arc
		(start 339.657436 -229.597204)
		(mid 339.383237 -229.521369)
		(end 339.106764 -229.588568)
		(width 0.088646)
		(layer "In11.Cu")
		(net "M_D_CPU0_SB_DQ<26>")
	)
	(arc
		(start 346.623894 -231.424226)
		(mid 346.455648 -231.628994)
		(end 346.319348 -231.85628)
		(width 0.088646)
		(layer "In11.Cu")
		(net "M_D_CPU0_SB_DQ<26>")
	)
	(arc
		(start 341.911432 -229.597204)
		(mid 341.724234 -229.647347)
		(end 341.537036 -229.597204)
		(width 0.088646)
		(layer "In11.Cu")
		(net "M_D_CPU0_SB_DQ<26>")
	)
	(arc
		(start 334.301084 -228.440488)
		(mid 334.220922 -228.168299)
		(end 334.018636 -227.969318)
		(width 0.088646)
		(layer "In11.Cu")
		(net "M_D_CPU0_SB_DQ<26>")
	)
	(arc
		(start 332.513178 -227.969318)
		(mid 332.422942 -228.007188)
		(end 332.32598 -228.020372)
		(width 0.088646)
		(layer "In11.Cu")
		(net "M_D_CPU0_SB_DQ<26>")
	)
	(arc
		(start 346.140278 -232.038906)
		(mid 345.95308 -232.089049)
		(end 345.765882 -232.038906)
		(width 0.088646)
		(layer "In11.Cu")
		(net "M_D_CPU0_SB_DQ<26>")
	)
	(arc
		(start 340.597236 -229.597204)
		(mid 340.323037 -229.521369)
		(end 340.046564 -229.588568)
		(width 0.088646)
		(layer "In11.Cu")
		(net "M_D_CPU0_SB_DQ<26>")
	)
	(arc
		(start 335.887822 -229.591108)
		(mid 335.60939 -229.521262)
		(end 335.332578 -229.597204)
		(width 0.088646)
		(layer "In11.Cu")
		(net "M_D_CPU0_SB_DQ<26>")
	)
	(segment
		(start 258.44754 -201.982832)
		(end 258.28498 -202.145392)
		(width 0.20066)
		(layer "F.Cu")
		(net "M_D_CPU0_SB_DQ<25>")
	)
	(segment
		(start 259.056378 -201.982832)
		(end 258.44754 -201.982832)
		(width 0.20066)
		(layer "F.Cu")
		(net "M_D_CPU0_SB_DQ<25>")
	)
	(segment
		(start 346.42298 -231.436418)
		(end 346.423234 -231.436164)
		(width 0.20066)
		(layer "F.Cu")
		(net "M_D_CPU0_SB_DQ<25>")
	)
	(segment
		(start 258.28498 -202.47356)
		(end 258.130548 -202.627992)
		(width 0.20066)
		(layer "F.Cu")
		(net "M_D_CPU0_SB_DQ<25>")
	)
	(segment
		(start 257.626104 -202.627992)
		(end 257.414776 -202.416664)
		(width 0.20066)
		(layer "F.Cu")
		(net "M_D_CPU0_SB_DQ<25>")
	)
	(segment
		(start 258.28498 -202.145392)
		(end 258.28498 -202.47356)
		(width 0.20066)
		(layer "F.Cu")
		(net "M_D_CPU0_SB_DQ<25>")
	)
	(segment
		(start 259.065268 -201.991722)
		(end 259.056378 -201.982832)
		(width 0.1016)
		(layer "F.Cu")
		(net "M_D_CPU0_SB_DQ<25>")
	)
	(segment
		(start 264.729214 -202.416664)
		(end 263.624314 -202.416664)
		(width 0.20066)
		(layer "F.Cu")
		(net "M_D_CPU0_SB_DQ<25>")
	)
	(segment
		(start 263.624314 -202.416664)
		(end 261.984998 -202.416664)
		(width 0.20066)
		(layer "F.Cu")
		(net "M_D_CPU0_SB_DQ<25>")
	)
	(segment
		(start 261.984998 -202.416664)
		(end 261.560056 -201.991722)
		(width 0.20066)
		(layer "F.Cu")
		(net "M_D_CPU0_SB_DQ<25>")
	)
	(segment
		(start 261.050786 -201.991722)
		(end 259.065268 -201.991722)
		(width 0.1016)
		(layer "F.Cu")
		(net "M_D_CPU0_SB_DQ<25>")
	)
	(segment
		(start 257.414776 -202.416664)
		(end 256.080514 -202.416664)
		(width 0.20066)
		(layer "F.Cu")
		(net "M_D_CPU0_SB_DQ<25>")
	)
	(segment
		(start 258.130548 -202.627992)
		(end 257.626104 -202.627992)
		(width 0.20066)
		(layer "F.Cu")
		(net "M_D_CPU0_SB_DQ<25>")
	)
	(segment
		(start 346.423234 -231.436164)
		(end 346.423234 -230.900478)
		(width 0.20066)
		(layer "F.Cu")
		(net "M_D_CPU0_SB_DQ<25>")
	)
	(segment
		(start 261.381494 -201.991722)
		(end 261.050786 -201.991722)
		(width 0.101854)
		(layer "F.Cu")
		(net "M_D_CPU0_SB_DQ<25>")
	)
	(segment
		(start 261.560056 -201.991722)
		(end 261.381494 -201.991722)
		(width 0.20066)
		(layer "F.Cu")
		(net "M_D_CPU0_SB_DQ<25>")
	)
	(segment
		(start 290.48583 -202.399138)
		(end 290.17087 -202.399138)
		(width 0.18288)
		(layer "In11.Cu")
		(net "M_D_CPU0_SB_DQ<25>")
	)
	(segment
		(start 293.793418 -201.993246)
		(end 293.63797 -202.148694)
		(width 0.18288)
		(layer "In11.Cu")
		(net "M_D_CPU0_SB_DQ<25>")
	)
	(segment
		(start 345.29649 -231.22509)
		(end 345.295982 -231.224836)
		(width 0.088646)
		(layer "In11.Cu")
		(net "M_D_CPU0_SB_DQ<25>")
	)
	(segment
		(start 274.850352 -202.051666)
		(end 274.657312 -201.858626)
		(width 0.18288)
		(layer "In11.Cu")
		(net "M_D_CPU0_SB_DQ<25>")
	)
	(segment
		(start 343.799922 -228.953568)
		(end 343.791032 -228.948488)
		(width 0.088646)
		(layer "In11.Cu")
		(net "M_D_CPU0_SB_DQ<25>")
	)
	(segment
		(start 303.741582 -202.158092)
		(end 301.554388 -202.158092)
		(width 0.18288)
		(layer "In11.Cu")
		(net "M_D_CPU0_SB_DQ<25>")
	)
	(segment
		(start 313.579256 -207.391762)
		(end 313.579256 -206.888842)
		(width 0.18288)
		(layer "In11.Cu")
		(net "M_D_CPU0_SB_DQ<25>")
	)
	(segment
		(start 275.551392 -202.336146)
		(end 275.358352 -202.529186)
		(width 0.18288)
		(layer "In11.Cu")
		(net "M_D_CPU0_SB_DQ<25>")
	)
	(segment
		(start 308.346094 -203.027026)
		(end 307.22316 -201.904092)
		(width 0.18288)
		(layer "In11.Cu")
		(net "M_D_CPU0_SB_DQ<25>")
	)
	(segment
		(start 335.050638 -228.477826)
		(end 335.050384 -228.459284)
		(width 0.088646)
		(layer "In11.Cu")
		(net "M_D_CPU0_SB_DQ<25>")
	)
	(segment
		(start 267.274802 -203.035408)
		(end 267.081762 -202.842368)
		(width 0.18288)
		(layer "In11.Cu")
		(net "M_D_CPU0_SB_DQ<25>")
	)
	(segment
		(start 320.942716 -217.012012)
		(end 320.942716 -214.133938)
		(width 0.18288)
		(layer "In11.Cu")
		(net "M_D_CPU0_SB_DQ<25>")
	)
	(segment
		(start 274.657312 -201.858626)
		(end 273.090894 -201.858626)
		(width 0.18288)
		(layer "In11.Cu")
		(net "M_D_CPU0_SB_DQ<25>")
	)
	(segment
		(start 275.043392 -202.529186)
		(end 274.850352 -202.336146)
		(width 0.18288)
		(layer "In11.Cu")
		(net "M_D_CPU0_SB_DQ<25>")
	)
	(segment
		(start 285.191962 -202.650598)
		(end 285.000192 -202.842368)
		(width 0.18288)
		(layer "In11.Cu")
		(net "M_D_CPU0_SB_DQ<25>")
	)
	(segment
		(start 265.872722 -203.514706)
		(end 265.872722 -203.035408)
		(width 0.18288)
		(layer "In11.Cu")
		(net "M_D_CPU0_SB_DQ<25>")
	)
	(segment
		(start 266.573762 -203.035408)
		(end 266.573762 -203.514706)
		(width 0.18288)
		(layer "In11.Cu")
		(net "M_D_CPU0_SB_DQ<25>")
	)
	(segment
		(start 330.179934 -226.24923)
		(end 320.942716 -217.012012)
		(width 0.18288)
		(layer "In11.Cu")
		(net "M_D_CPU0_SB_DQ<25>")
	)
	(segment
		(start 313.579256 -206.888842)
		(end 311.85104 -205.160626)
		(width 0.18288)
		(layer "In11.Cu")
		(net "M_D_CPU0_SB_DQ<25>")
	)
	(segment
		(start 344.269568 -229.767384)
		(end 344.260678 -229.762304)
		(width 0.088646)
		(layer "In11.Cu")
		(net "M_D_CPU0_SB_DQ<25>")
	)
	(segment
		(start 266.766802 -202.842368)
		(end 266.573762 -203.035408)
		(width 0.18288)
		(layer "In11.Cu")
		(net "M_D_CPU0_SB_DQ<25>")
	)
	(segment
		(start 334.871568 -228.139498)
		(end 334.862678 -228.134418)
		(width 0.088646)
		(layer "In11.Cu")
		(net "M_D_CPU0_SB_DQ<25>")
	)
	(segment
		(start 334.018636 -227.320602)
		(end 334.008222 -227.326698)
		(width 0.088646)
		(layer "In11.Cu")
		(net "M_D_CPU0_SB_DQ<25>")
	)
	(segment
		(start 266.573762 -203.514706)
		(end 266.380722 -203.707746)
		(width 0.18288)
		(layer "In11.Cu")
		(net "M_D_CPU0_SB_DQ<25>")
	)
	(segment
		(start 285.000192 -202.842368)
		(end 283.142436 -202.842368)
		(width 0.18288)
		(layer "In11.Cu")
		(net "M_D_CPU0_SB_DQ<25>")
	)
	(segment
		(start 288.356294 -201.858626)
		(end 288.178494 -202.036426)
		(width 0.18288)
		(layer "In11.Cu")
		(net "M_D_CPU0_SB_DQ<25>")
	)
	(segment
		(start 330.66736 -226.51212)
		(end 330.66736 -226.317302)
		(width 0.088646)
		(layer "In11.Cu")
		(net "M_D_CPU0_SB_DQ<25>")
	)
	(segment
		(start 345.699588 -231.208072)
		(end 345.670378 -231.22509)
		(width 0.088646)
		(layer "In11.Cu")
		(net "M_D_CPU0_SB_DQ<25>")
	)
	(segment
		(start 340.986364 -228.957124)
		(end 340.971632 -228.948488)
		(width 0.088646)
		(layer "In11.Cu")
		(net "M_D_CPU0_SB_DQ<25>")
	)
	(segment
		(start 330.313538 -226.24923)
		(end 330.179934 -226.24923)
		(width 0.18288)
		(layer "In11.Cu")
		(net "M_D_CPU0_SB_DQ<25>")
	)
	(segment
		(start 267.274802 -203.640436)
		(end 267.274802 -203.035408)
		(width 0.18288)
		(layer "In11.Cu")
		(net "M_D_CPU0_SB_DQ<25>")
	)
	(segment
		(start 275.358352 -202.529186)
		(end 275.043392 -202.529186)
		(width 0.18288)
		(layer "In11.Cu")
		(net "M_D_CPU0_SB_DQ<25>")
	)
	(segment
		(start 266.065762 -203.707746)
		(end 265.872722 -203.514706)
		(width 0.18288)
		(layer "In11.Cu")
		(net "M_D_CPU0_SB_DQ<25>")
	)
	(segment
		(start 290.87191 -201.858626)
		(end 290.67887 -202.051666)
		(width 0.18288)
		(layer "In11.Cu")
		(net "M_D_CPU0_SB_DQ<25>")
	)
	(segment
		(start 292.064694 -201.858626)
		(end 290.87191 -201.858626)
		(width 0.18288)
		(layer "In11.Cu")
		(net "M_D_CPU0_SB_DQ<25>")
	)
	(segment
		(start 275.744432 -201.858626)
		(end 275.551392 -202.051666)
		(width 0.18288)
		(layer "In11.Cu")
		(net "M_D_CPU0_SB_DQ<25>")
	)
	(segment
		(start 278.501094 -202.214226)
		(end 277.307294 -202.214226)
		(width 0.18288)
		(layer "In11.Cu")
		(net "M_D_CPU0_SB_DQ<25>")
	)
	(segment
		(start 314.39739 -208.209896)
		(end 313.579256 -207.391762)
		(width 0.18288)
		(layer "In11.Cu")
		(net "M_D_CPU0_SB_DQ<25>")
	)
	(segment
		(start 265.154918 -202.842368)
		(end 264.729214 -202.416664)
		(width 0.18288)
		(layer "In11.Cu")
		(net "M_D_CPU0_SB_DQ<25>")
	)
	(segment
		(start 276.951694 -201.858626)
		(end 275.744432 -201.858626)
		(width 0.18288)
		(layer "In11.Cu")
		(net "M_D_CPU0_SB_DQ<25>")
	)
	(segment
		(start 280.919174 -201.88555)
		(end 280.814526 -201.990198)
		(width 0.18288)
		(layer "In11.Cu")
		(net "M_D_CPU0_SB_DQ<25>")
	)
	(segment
		(start 272.278094 -202.671426)
		(end 269.636494 -202.671426)
		(width 0.18288)
		(layer "In11.Cu")
		(net "M_D_CPU0_SB_DQ<25>")
	)
	(segment
		(start 330.599288 -226.24923)
		(end 330.313538 -226.24923)
		(width 0.088646)
		(layer "In11.Cu")
		(net "M_D_CPU0_SB_DQ<25>")
	)
	(segment
		(start 344.730832 -230.57612)
		(end 344.71864 -230.569008)
		(width 0.088646)
		(layer "In11.Cu")
		(net "M_D_CPU0_SB_DQ<25>")
	)
	(segment
		(start 267.467842 -203.833476)
		(end 267.274802 -203.640436)
		(width 0.18288)
		(layer "In11.Cu")
		(net "M_D_CPU0_SB_DQ<25>")
	)
	(segment
		(start 337.227164 -228.957124)
		(end 337.212432 -228.948488)
		(width 0.088646)
		(layer "In11.Cu")
		(net "M_D_CPU0_SB_DQ<25>")
	)
	(segment
		(start 303.995582 -201.904092)
		(end 303.741582 -202.158092)
		(width 0.18288)
		(layer "In11.Cu")
		(net "M_D_CPU0_SB_DQ<25>")
	)
	(segment
		(start 297.138598 -201.87793)
		(end 296.042842 -201.87793)
		(width 0.18288)
		(layer "In11.Cu")
		(net "M_D_CPU0_SB_DQ<25>")
	)
	(segment
		(start 342.861392 -228.954584)
		(end 342.850978 -228.948488)
		(width 0.088646)
		(layer "In11.Cu")
		(net "M_D_CPU0_SB_DQ<25>")
	)
	(segment
		(start 267.975842 -203.623164)
		(end 267.76553 -203.833476)
		(width 0.18288)
		(layer "In11.Cu")
		(net "M_D_CPU0_SB_DQ<25>")
	)
	(segment
		(start 273.090894 -201.858626)
		(end 272.278094 -202.671426)
		(width 0.18288)
		(layer "In11.Cu")
		(net "M_D_CPU0_SB_DQ<25>")
	)
	(segment
		(start 285.862522 -202.650598)
		(end 285.191962 -202.650598)
		(width 0.18288)
		(layer "In11.Cu")
		(net "M_D_CPU0_SB_DQ<25>")
	)
	(segment
		(start 275.551392 -202.051666)
		(end 275.551392 -202.336146)
		(width 0.18288)
		(layer "In11.Cu")
		(net "M_D_CPU0_SB_DQ<25>")
	)
	(segment
		(start 308.828694 -203.027026)
		(end 308.346094 -203.027026)
		(width 0.18288)
		(layer "In11.Cu")
		(net "M_D_CPU0_SB_DQ<25>")
	)
	(segment
		(start 301.554388 -202.158092)
		(end 300.872398 -202.840082)
		(width 0.18288)
		(layer "In11.Cu")
		(net "M_D_CPU0_SB_DQ<25>")
	)
	(segment
		(start 289.97783 -202.051666)
		(end 289.78479 -201.858626)
		(width 0.18288)
		(layer "In11.Cu")
		(net "M_D_CPU0_SB_DQ<25>")
	)
	(segment
		(start 300.872398 -202.840082)
		(end 298.10075 -202.840082)
		(width 0.18288)
		(layer "In11.Cu")
		(net "M_D_CPU0_SB_DQ<25>")
	)
	(segment
		(start 315.018674 -208.209896)
		(end 314.39739 -208.209896)
		(width 0.18288)
		(layer "In11.Cu")
		(net "M_D_CPU0_SB_DQ<25>")
	)
	(segment
		(start 290.67887 -202.051666)
		(end 290.67887 -202.206098)
		(width 0.18288)
		(layer "In11.Cu")
		(net "M_D_CPU0_SB_DQ<25>")
	)
	(segment
		(start 311.85104 -205.160626)
		(end 310.962294 -205.160626)
		(width 0.18288)
		(layer "In11.Cu")
		(net "M_D_CPU0_SB_DQ<25>")
	)
	(segment
		(start 283.142436 -202.842368)
		(end 282.185618 -201.88555)
		(width 0.18288)
		(layer "In11.Cu")
		(net "M_D_CPU0_SB_DQ<25>")
	)
	(segment
		(start 266.380722 -203.707746)
		(end 266.065762 -203.707746)
		(width 0.18288)
		(layer "In11.Cu")
		(net "M_D_CPU0_SB_DQ<25>")
	)
	(segment
		(start 289.97783 -202.206098)
		(end 289.97783 -202.051666)
		(width 0.18288)
		(layer "In11.Cu")
		(net "M_D_CPU0_SB_DQ<25>")
	)
	(segment
		(start 343.978484 -229.28834)
		(end 343.978484 -229.272846)
		(width 0.088646)
		(layer "In11.Cu")
		(net "M_D_CPU0_SB_DQ<25>")
	)
	(segment
		(start 295.927526 -201.993246)
		(end 293.793418 -201.993246)
		(width 0.18288)
		(layer "In11.Cu")
		(net "M_D_CPU0_SB_DQ<25>")
	)
	(segment
		(start 268.168882 -202.842368)
		(end 267.975842 -203.035408)
		(width 0.18288)
		(layer "In11.Cu")
		(net "M_D_CPU0_SB_DQ<25>")
	)
	(segment
		(start 286.476694 -202.036426)
		(end 285.862522 -202.650598)
		(width 0.18288)
		(layer "In11.Cu")
		(net "M_D_CPU0_SB_DQ<25>")
	)
	(segment
		(start 338.166964 -228.957124)
		(end 338.152232 -228.948488)
		(width 0.088646)
		(layer "In11.Cu")
		(net "M_D_CPU0_SB_DQ<25>")
	)
	(segment
		(start 274.850352 -202.336146)
		(end 274.850352 -202.051666)
		(width 0.18288)
		(layer "In11.Cu")
		(net "M_D_CPU0_SB_DQ<25>")
	)
	(segment
		(start 310.962294 -205.160626)
		(end 308.828694 -203.027026)
		(width 0.18288)
		(layer "In11.Cu")
		(net "M_D_CPU0_SB_DQ<25>")
	)
	(segment
		(start 341.921846 -228.954584)
		(end 341.911432 -228.948488)
		(width 0.088646)
		(layer "In11.Cu")
		(net "M_D_CPU0_SB_DQ<25>")
	)
	(segment
		(start 340.046564 -228.957124)
		(end 340.031832 -228.948488)
		(width 0.088646)
		(layer "In11.Cu")
		(net "M_D_CPU0_SB_DQ<25>")
	)
	(segment
		(start 332.32598 -227.270056)
		(end 331.425296 -227.270056)
		(width 0.088646)
		(layer "In11.Cu")
		(net "M_D_CPU0_SB_DQ<25>")
	)
	(segment
		(start 307.22316 -201.904092)
		(end 303.995582 -201.904092)
		(width 0.18288)
		(layer "In11.Cu")
		(net "M_D_CPU0_SB_DQ<25>")
	)
	(segment
		(start 335.332832 -228.948488)
		(end 335.332832 -228.948742)
		(width 0.088646)
		(layer "In11.Cu")
		(net "M_D_CPU0_SB_DQ<25>")
	)
	(segment
		(start 292.354762 -202.148694)
		(end 292.064694 -201.858626)
		(width 0.18288)
		(layer "In11.Cu")
		(net "M_D_CPU0_SB_DQ<25>")
	)
	(segment
		(start 265.872722 -203.035408)
		(end 265.679682 -202.842368)
		(width 0.18288)
		(layer "In11.Cu")
		(net "M_D_CPU0_SB_DQ<25>")
	)
	(segment
		(start 269.465552 -202.842368)
		(end 268.168882 -202.842368)
		(width 0.18288)
		(layer "In11.Cu")
		(net "M_D_CPU0_SB_DQ<25>")
	)
	(segment
		(start 298.10075 -202.840082)
		(end 297.138598 -201.87793)
		(width 0.18288)
		(layer "In11.Cu")
		(net "M_D_CPU0_SB_DQ<25>")
	)
	(segment
		(start 335.050384 -228.459284)
		(end 335.05013 -228.458776)
		(width 0.088646)
		(layer "In11.Cu")
		(net "M_D_CPU0_SB_DQ<25>")
	)
	(segment
		(start 293.63797 -202.148694)
		(end 292.354762 -202.148694)
		(width 0.18288)
		(layer "In11.Cu")
		(net "M_D_CPU0_SB_DQ<25>")
	)
	(segment
		(start 330.66736 -226.317302)
		(end 330.599288 -226.24923)
		(width 0.088646)
		(layer "In11.Cu")
		(net "M_D_CPU0_SB_DQ<25>")
	)
	(segment
		(start 267.081762 -202.842368)
		(end 266.766802 -202.842368)
		(width 0.18288)
		(layer "In11.Cu")
		(net "M_D_CPU0_SB_DQ<25>")
	)
	(segment
		(start 290.17087 -202.399138)
		(end 289.97783 -202.206098)
		(width 0.18288)
		(layer "In11.Cu")
		(net "M_D_CPU0_SB_DQ<25>")
	)
	(segment
		(start 282.185618 -201.88555)
		(end 280.919174 -201.88555)
		(width 0.18288)
		(layer "In11.Cu")
		(net "M_D_CPU0_SB_DQ<25>")
	)
	(segment
		(start 334.58023 -227.654866)
		(end 334.58023 -227.636324)
		(width 0.088646)
		(layer "In11.Cu")
		(net "M_D_CPU0_SB_DQ<25>")
	)
	(segment
		(start 267.76553 -203.833476)
		(end 267.467842 -203.833476)
		(width 0.18288)
		(layer "In11.Cu")
		(net "M_D_CPU0_SB_DQ<25>")
	)
	(segment
		(start 290.67887 -202.206098)
		(end 290.48583 -202.399138)
		(width 0.18288)
		(layer "In11.Cu")
		(net "M_D_CPU0_SB_DQ<25>")
	)
	(segment
		(start 277.307294 -202.214226)
		(end 276.951694 -201.858626)
		(width 0.18288)
		(layer "In11.Cu")
		(net "M_D_CPU0_SB_DQ<25>")
	)
	(segment
		(start 331.425296 -227.270056)
		(end 330.66736 -226.51212)
		(width 0.088646)
		(layer "In11.Cu")
		(net "M_D_CPU0_SB_DQ<25>")
	)
	(segment
		(start 346.423234 -230.900478)
		(end 345.699588 -231.208072)
		(width 0.088646)
		(layer "In11.Cu")
		(net "M_D_CPU0_SB_DQ<25>")
	)
	(segment
		(start 265.679682 -202.842368)
		(end 265.154918 -202.842368)
		(width 0.18288)
		(layer "In11.Cu")
		(net "M_D_CPU0_SB_DQ<25>")
	)
	(segment
		(start 289.78479 -201.858626)
		(end 288.356294 -201.858626)
		(width 0.18288)
		(layer "In11.Cu")
		(net "M_D_CPU0_SB_DQ<25>")
	)
	(segment
		(start 296.042842 -201.87793)
		(end 295.927526 -201.993246)
		(width 0.18288)
		(layer "In11.Cu")
		(net "M_D_CPU0_SB_DQ<25>")
	)
	(segment
		(start 320.942716 -214.133938)
		(end 315.018674 -208.209896)
		(width 0.18288)
		(layer "In11.Cu")
		(net "M_D_CPU0_SB_DQ<25>")
	)
	(segment
		(start 336.287364 -228.957124)
		(end 336.272632 -228.948488)
		(width 0.088646)
		(layer "In11.Cu")
		(net "M_D_CPU0_SB_DQ<25>")
	)
	(segment
		(start 288.178494 -202.036426)
		(end 286.476694 -202.036426)
		(width 0.18288)
		(layer "In11.Cu")
		(net "M_D_CPU0_SB_DQ<25>")
	)
	(segment
		(start 267.975842 -203.035408)
		(end 267.975842 -203.623164)
		(width 0.18288)
		(layer "In11.Cu")
		(net "M_D_CPU0_SB_DQ<25>")
	)
	(segment
		(start 280.814526 -201.990198)
		(end 278.725122 -201.990198)
		(width 0.18288)
		(layer "In11.Cu")
		(net "M_D_CPU0_SB_DQ<25>")
	)
	(segment
		(start 278.725122 -201.990198)
		(end 278.501094 -202.214226)
		(width 0.18288)
		(layer "In11.Cu")
		(net "M_D_CPU0_SB_DQ<25>")
	)
	(segment
		(start 269.636494 -202.671426)
		(end 269.465552 -202.842368)
		(width 0.18288)
		(layer "In11.Cu")
		(net "M_D_CPU0_SB_DQ<25>")
	)
	(arc
		(start 337.777836 -228.948488)
		(mid 337.503637 -229.024323)
		(end 337.227164 -228.957124)
		(width 0.088646)
		(layer "In11.Cu")
		(net "M_D_CPU0_SB_DQ<25>")
	)
	(arc
		(start 340.597236 -228.948488)
		(mid 340.323037 -229.024323)
		(end 340.046564 -228.957124)
		(width 0.088646)
		(layer "In11.Cu")
		(net "M_D_CPU0_SB_DQ<25>")
	)
	(arc
		(start 334.862678 -228.134418)
		(mid 334.658343 -227.931813)
		(end 334.58023 -227.654866)
		(width 0.088646)
		(layer "In11.Cu")
		(net "M_D_CPU0_SB_DQ<25>")
	)
	(arc
		(start 343.416636 -228.948488)
		(mid 343.139823 -229.024358)
		(end 342.861392 -228.954584)
		(width 0.088646)
		(layer "In11.Cu")
		(net "M_D_CPU0_SB_DQ<25>")
	)
	(arc
		(start 334.393032 -227.320602)
		(mid 334.205834 -227.270459)
		(end 334.018636 -227.320602)
		(width 0.088646)
		(layer "In11.Cu")
		(net "M_D_CPU0_SB_DQ<25>")
	)
	(arc
		(start 341.537036 -228.948488)
		(mid 341.262837 -229.024323)
		(end 340.986364 -228.957124)
		(width 0.088646)
		(layer "In11.Cu")
		(net "M_D_CPU0_SB_DQ<25>")
	)
	(arc
		(start 333.452978 -227.320602)
		(mid 333.26578 -227.270459)
		(end 333.078582 -227.320602)
		(width 0.088646)
		(layer "In11.Cu")
		(net "M_D_CPU0_SB_DQ<25>")
	)
	(arc
		(start 332.513178 -227.320602)
		(mid 332.422906 -227.283003)
		(end 332.32598 -227.270056)
		(width 0.088646)
		(layer "In11.Cu")
		(net "M_D_CPU0_SB_DQ<25>")
	)
	(arc
		(start 335.05013 -228.458776)
		(mid 335.002451 -228.275876)
		(end 334.871568 -228.139498)
		(width 0.088646)
		(layer "In11.Cu")
		(net "M_D_CPU0_SB_DQ<25>")
	)
	(arc
		(start 340.971632 -228.948488)
		(mid 340.784434 -228.898345)
		(end 340.597236 -228.948488)
		(width 0.088646)
		(layer "In11.Cu")
		(net "M_D_CPU0_SB_DQ<25>")
	)
	(arc
		(start 335.332832 -228.948742)
		(mid 335.13079 -228.749819)
		(end 335.050638 -228.477826)
		(width 0.088646)
		(layer "In11.Cu")
		(net "M_D_CPU0_SB_DQ<25>")
	)
	(arc
		(start 333.078582 -227.320602)
		(mid 332.79588 -227.396378)
		(end 332.513178 -227.320602)
		(width 0.088646)
		(layer "In11.Cu")
		(net "M_D_CPU0_SB_DQ<25>")
	)
	(arc
		(start 343.791032 -228.948488)
		(mid 343.603834 -228.898345)
		(end 343.416636 -228.948488)
		(width 0.088646)
		(layer "In11.Cu")
		(net "M_D_CPU0_SB_DQ<25>")
	)
	(arc
		(start 343.978484 -229.272846)
		(mid 343.930805 -229.089946)
		(end 343.799922 -228.953568)
		(width 0.088646)
		(layer "In11.Cu")
		(net "M_D_CPU0_SB_DQ<25>")
	)
	(arc
		(start 345.285822 -231.21874)
		(mid 345.177195 -231.11638)
		(end 345.117166 -230.979726)
		(width 0.088646)
		(layer "In11.Cu")
		(net "M_D_CPU0_SB_DQ<25>")
	)
	(arc
		(start 344.71864 -230.569008)
		(mid 344.520412 -230.36316)
		(end 344.44813 -230.086662)
		(width 0.088646)
		(layer "In11.Cu")
		(net "M_D_CPU0_SB_DQ<25>")
	)
	(arc
		(start 345.670378 -231.22509)
		(mid 345.483434 -231.275174)
		(end 345.29649 -231.22509)
		(width 0.088646)
		(layer "In11.Cu")
		(net "M_D_CPU0_SB_DQ<25>")
	)
	(arc
		(start 345.295982 -231.224836)
		(mid 345.290866 -231.221848)
		(end 345.285822 -231.21874)
		(width 0.088646)
		(layer "In11.Cu")
		(net "M_D_CPU0_SB_DQ<25>")
	)
	(arc
		(start 338.717636 -228.948488)
		(mid 338.443437 -229.024323)
		(end 338.166964 -228.957124)
		(width 0.088646)
		(layer "In11.Cu")
		(net "M_D_CPU0_SB_DQ<25>")
	)
	(arc
		(start 336.838036 -228.948488)
		(mid 336.563837 -229.024323)
		(end 336.287364 -228.957124)
		(width 0.088646)
		(layer "In11.Cu")
		(net "M_D_CPU0_SB_DQ<25>")
	)
	(arc
		(start 342.476582 -228.948488)
		(mid 342.200023 -229.024231)
		(end 341.921846 -228.954584)
		(width 0.088646)
		(layer "In11.Cu")
		(net "M_D_CPU0_SB_DQ<25>")
	)
	(arc
		(start 334.008222 -227.326698)
		(mid 333.72979 -227.396544)
		(end 333.452978 -227.320602)
		(width 0.088646)
		(layer "In11.Cu")
		(net "M_D_CPU0_SB_DQ<25>")
	)
	(arc
		(start 334.58023 -227.636324)
		(mid 334.52796 -227.453959)
		(end 334.393032 -227.320602)
		(width 0.088646)
		(layer "In11.Cu")
		(net "M_D_CPU0_SB_DQ<25>")
	)
	(arc
		(start 344.44813 -230.086662)
		(mid 344.400451 -229.903762)
		(end 344.269568 -229.767384)
		(width 0.088646)
		(layer "In11.Cu")
		(net "M_D_CPU0_SB_DQ<25>")
	)
	(arc
		(start 344.260678 -229.762304)
		(mid 344.057855 -229.562073)
		(end 343.978484 -229.28834)
		(width 0.088646)
		(layer "In11.Cu")
		(net "M_D_CPU0_SB_DQ<25>")
	)
	(arc
		(start 339.657436 -228.948488)
		(mid 339.374734 -229.024264)
		(end 339.092032 -228.948488)
		(width 0.088646)
		(layer "In11.Cu")
		(net "M_D_CPU0_SB_DQ<25>")
	)
	(arc
		(start 337.212432 -228.948488)
		(mid 337.025234 -228.898345)
		(end 336.838036 -228.948488)
		(width 0.088646)
		(layer "In11.Cu")
		(net "M_D_CPU0_SB_DQ<25>")
	)
	(arc
		(start 340.031832 -228.948488)
		(mid 339.844634 -228.898345)
		(end 339.657436 -228.948488)
		(width 0.088646)
		(layer "In11.Cu")
		(net "M_D_CPU0_SB_DQ<25>")
	)
	(arc
		(start 335.898236 -228.948488)
		(mid 335.615534 -229.024264)
		(end 335.332832 -228.948488)
		(width 0.088646)
		(layer "In11.Cu")
		(net "M_D_CPU0_SB_DQ<25>")
	)
	(arc
		(start 341.911432 -228.948488)
		(mid 341.724234 -228.898345)
		(end 341.537036 -228.948488)
		(width 0.088646)
		(layer "In11.Cu")
		(net "M_D_CPU0_SB_DQ<25>")
	)
	(arc
		(start 338.152232 -228.948488)
		(mid 337.965034 -228.898345)
		(end 337.777836 -228.948488)
		(width 0.088646)
		(layer "In11.Cu")
		(net "M_D_CPU0_SB_DQ<25>")
	)
	(arc
		(start 339.092032 -228.948488)
		(mid 338.904834 -228.898345)
		(end 338.717636 -228.948488)
		(width 0.088646)
		(layer "In11.Cu")
		(net "M_D_CPU0_SB_DQ<25>")
	)
	(arc
		(start 345.016836 -230.79583)
		(mid 344.881037 -230.6766)
		(end 344.730832 -230.57612)
		(width 0.088646)
		(layer "In11.Cu")
		(net "M_D_CPU0_SB_DQ<25>")
	)
	(arc
		(start 336.272632 -228.948488)
		(mid 336.085434 -228.898345)
		(end 335.898236 -228.948488)
		(width 0.088646)
		(layer "In11.Cu")
		(net "M_D_CPU0_SB_DQ<25>")
	)
	(arc
		(start 342.850978 -228.948488)
		(mid 342.66378 -228.898345)
		(end 342.476582 -228.948488)
		(width 0.088646)
		(layer "In11.Cu")
		(net "M_D_CPU0_SB_DQ<25>")
	)
	(arc
		(start 345.117166 -230.979726)
		(mid 345.080264 -230.880538)
		(end 345.016836 -230.79583)
		(width 0.088646)
		(layer "In11.Cu")
		(net "M_D_CPU0_SB_DQ<25>")
	)
	(segment
		(start 257.653536 -204.355446)
		(end 257.414776 -204.116686)
		(width 0.20066)
		(layer "F.Cu")
		(net "M_D_CPU0_SB_DQ<24>")
	)
	(segment
		(start 346.893134 -232.250488)
		(end 346.89288 -232.250234)
		(width 0.20066)
		(layer "F.Cu")
		(net "M_D_CPU0_SB_DQ<24>")
	)
	(segment
		(start 261.830312 -203.691744)
		(end 261.381494 -203.691744)
		(width 0.20066)
		(layer "F.Cu")
		(net "M_D_CPU0_SB_DQ<24>")
	)
	(segment
		(start 262.255254 -204.116686)
		(end 261.830312 -203.691744)
		(width 0.20066)
		(layer "F.Cu")
		(net "M_D_CPU0_SB_DQ<24>")
	)
	(segment
		(start 257.414776 -204.116686)
		(end 256.080514 -204.116686)
		(width 0.20066)
		(layer "F.Cu")
		(net "M_D_CPU0_SB_DQ<24>")
	)
	(segment
		(start 259.31241 -203.691744)
		(end 259.064506 -203.691744)
		(width 0.101854)
		(layer "F.Cu")
		(net "M_D_CPU0_SB_DQ<24>")
	)
	(segment
		(start 258.28498 -203.893166)
		(end 258.28498 -204.182726)
		(width 0.20066)
		(layer "F.Cu")
		(net "M_D_CPU0_SB_DQ<24>")
	)
	(segment
		(start 259.064506 -203.691744)
		(end 259.056378 -203.683616)
		(width 0.101854)
		(layer "F.Cu")
		(net "M_D_CPU0_SB_DQ<24>")
	)
	(segment
		(start 258.11226 -204.355446)
		(end 257.653536 -204.355446)
		(width 0.20066)
		(layer "F.Cu")
		(net "M_D_CPU0_SB_DQ<24>")
	)
	(segment
		(start 259.056378 -203.683616)
		(end 258.49453 -203.683616)
		(width 0.20066)
		(layer "F.Cu")
		(net "M_D_CPU0_SB_DQ<24>")
	)
	(segment
		(start 264.729214 -204.116686)
		(end 263.624314 -204.116686)
		(width 0.20066)
		(layer "F.Cu")
		(net "M_D_CPU0_SB_DQ<24>")
	)
	(segment
		(start 258.49453 -203.683616)
		(end 258.28498 -203.893166)
		(width 0.20066)
		(layer "F.Cu")
		(net "M_D_CPU0_SB_DQ<24>")
	)
	(segment
		(start 261.381494 -203.691744)
		(end 259.31241 -203.691744)
		(width 0.1016)
		(layer "F.Cu")
		(net "M_D_CPU0_SB_DQ<24>")
	)
	(segment
		(start 258.28498 -204.182726)
		(end 258.11226 -204.355446)
		(width 0.20066)
		(layer "F.Cu")
		(net "M_D_CPU0_SB_DQ<24>")
	)
	(segment
		(start 263.624314 -204.116686)
		(end 262.255254 -204.116686)
		(width 0.20066)
		(layer "F.Cu")
		(net "M_D_CPU0_SB_DQ<24>")
	)
	(segment
		(start 346.89288 -232.250234)
		(end 346.89288 -231.714548)
		(width 0.20066)
		(layer "F.Cu")
		(net "M_D_CPU0_SB_DQ<24>")
	)
	(segment
		(start 314.19673 -209.452718)
		(end 312.382408 -207.638396)
		(width 0.18288)
		(layer "In11.Cu")
		(net "M_D_CPU0_SB_DQ<24>")
	)
	(segment
		(start 270.650716 -205.09357)
		(end 270.650716 -204.540866)
		(width 0.18288)
		(layer "In11.Cu")
		(net "M_D_CPU0_SB_DQ<24>")
	)
	(segment
		(start 283.140658 -204.54239)
		(end 282.160218 -203.56195)
		(width 0.18288)
		(layer "In11.Cu")
		(net "M_D_CPU0_SB_DQ<24>")
	)
	(segment
		(start 271.351756 -204.540866)
		(end 271.351756 -205.09357)
		(width 0.18288)
		(layer "In11.Cu")
		(net "M_D_CPU0_SB_DQ<24>")
	)
	(segment
		(start 266.539218 -205.24978)
		(end 266.346178 -205.44282)
		(width 0.18288)
		(layer "In11.Cu")
		(net "M_D_CPU0_SB_DQ<24>")
	)
	(segment
		(start 288.737294 -204.424026)
		(end 285.118556 -204.424026)
		(width 0.18288)
		(layer "In11.Cu")
		(net "M_D_CPU0_SB_DQ<24>")
	)
	(segment
		(start 330.84516 -227.327714)
		(end 330.313538 -227.327714)
		(width 0.088646)
		(layer "In11.Cu")
		(net "M_D_CPU0_SB_DQ<24>")
	)
	(segment
		(start 267.941298 -205.24978)
		(end 267.748258 -205.44282)
		(width 0.18288)
		(layer "In11.Cu")
		(net "M_D_CPU0_SB_DQ<24>")
	)
	(segment
		(start 332.32598 -228.210618)
		(end 331.728064 -228.210618)
		(width 0.088646)
		(layer "In11.Cu")
		(net "M_D_CPU0_SB_DQ<24>")
	)
	(segment
		(start 344.269568 -231.39527)
		(end 344.260678 -231.39019)
		(width 0.088646)
		(layer "In11.Cu")
		(net "M_D_CPU0_SB_DQ<24>")
	)
	(segment
		(start 314.762896 -209.452718)
		(end 314.19673 -209.452718)
		(width 0.18288)
		(layer "In11.Cu")
		(net "M_D_CPU0_SB_DQ<24>")
	)
	(segment
		(start 334.110584 -228.468936)
		(end 334.110584 -228.45903)
		(width 0.088646)
		(layer "In11.Cu")
		(net "M_D_CPU0_SB_DQ<24>")
	)
	(segment
		(start 338.247736 -229.762304)
		(end 338.237322 -229.7684)
		(width 0.088646)
		(layer "In11.Cu")
		(net "M_D_CPU0_SB_DQ<24>")
	)
	(segment
		(start 331.728064 -228.210618)
		(end 330.84516 -227.327714)
		(width 0.088646)
		(layer "In11.Cu")
		(net "M_D_CPU0_SB_DQ<24>")
	)
	(segment
		(start 340.127082 -229.762304)
		(end 340.11235 -229.77094)
		(width 0.088646)
		(layer "In11.Cu")
		(net "M_D_CPU0_SB_DQ<24>")
	)
	(segment
		(start 282.160218 -203.56195)
		(end 281.542236 -203.56195)
		(width 0.18288)
		(layer "In11.Cu")
		(net "M_D_CPU0_SB_DQ<24>")
	)
	(segment
		(start 291.570664 -204.867256)
		(end 289.180524 -204.867256)
		(width 0.18288)
		(layer "In11.Cu")
		(net "M_D_CPU0_SB_DQ<24>")
	)
	(segment
		(start 266.031218 -205.44282)
		(end 265.838178 -205.24978)
		(width 0.18288)
		(layer "In11.Cu")
		(net "M_D_CPU0_SB_DQ<24>")
	)
	(segment
		(start 303.068228 -203.580492)
		(end 302.37049 -204.27823)
		(width 0.18288)
		(layer "In11.Cu")
		(net "M_D_CPU0_SB_DQ<24>")
	)
	(segment
		(start 319.883282 -217.463878)
		(end 319.883282 -214.573104)
		(width 0.18288)
		(layer "In11.Cu")
		(net "M_D_CPU0_SB_DQ<24>")
	)
	(segment
		(start 277.104094 -203.662026)
		(end 273.725894 -203.662026)
		(width 0.18288)
		(layer "In11.Cu")
		(net "M_D_CPU0_SB_DQ<24>")
	)
	(segment
		(start 298.008548 -204.542644)
		(end 297.155108 -203.689204)
		(width 0.18288)
		(layer "In11.Cu")
		(net "M_D_CPU0_SB_DQ<24>")
	)
	(segment
		(start 302.37049 -204.27823)
		(end 300.0629 -204.27823)
		(width 0.18288)
		(layer "In11.Cu")
		(net "M_D_CPU0_SB_DQ<24>")
	)
	(segment
		(start 267.240258 -204.735176)
		(end 267.047218 -204.542136)
		(width 0.18288)
		(layer "In11.Cu")
		(net "M_D_CPU0_SB_DQ<24>")
	)
	(segment
		(start 345.681046 -232.210102)
		(end 345.670632 -232.204006)
		(width 0.088646)
		(layer "In11.Cu")
		(net "M_D_CPU0_SB_DQ<24>")
	)
	(segment
		(start 342.006682 -229.762304)
		(end 341.99195 -229.77094)
		(width 0.088646)
		(layer "In11.Cu")
		(net "M_D_CPU0_SB_DQ<24>")
	)
	(segment
		(start 292.039294 -204.398626)
		(end 291.570664 -204.867256)
		(width 0.18288)
		(layer "In11.Cu")
		(net "M_D_CPU0_SB_DQ<24>")
	)
	(segment
		(start 344.745564 -232.212642)
		(end 344.730832 -232.204006)
		(width 0.088646)
		(layer "In11.Cu")
		(net "M_D_CPU0_SB_DQ<24>")
	)
	(segment
		(start 343.791032 -230.57612)
		(end 343.784936 -230.572564)
		(width 0.088646)
		(layer "In11.Cu")
		(net "M_D_CPU0_SB_DQ<24>")
	)
	(segment
		(start 293.040562 -204.398626)
		(end 292.039294 -204.398626)
		(width 0.18288)
		(layer "In11.Cu")
		(net "M_D_CPU0_SB_DQ<24>")
	)
	(segment
		(start 337.307682 -229.762304)
		(end 337.29295 -229.77094)
		(width 0.088646)
		(layer "In11.Cu")
		(net "M_D_CPU0_SB_DQ<24>")
	)
	(segment
		(start 268.134338 -204.542136)
		(end 267.941298 -204.735176)
		(width 0.18288)
		(layer "In11.Cu")
		(net "M_D_CPU0_SB_DQ<24>")
	)
	(segment
		(start 267.748258 -205.44282)
		(end 267.433298 -205.44282)
		(width 0.18288)
		(layer "In11.Cu")
		(net "M_D_CPU0_SB_DQ<24>")
	)
	(segment
		(start 332.998064 -228.143308)
		(end 332.983332 -228.134672)
		(width 0.088646)
		(layer "In11.Cu")
		(net "M_D_CPU0_SB_DQ<24>")
	)
	(segment
		(start 267.433298 -205.44282)
		(end 267.240258 -205.24978)
		(width 0.18288)
		(layer "In11.Cu")
		(net "M_D_CPU0_SB_DQ<24>")
	)
	(segment
		(start 334.58023 -229.282752)
		(end 334.58023 -229.26421)
		(width 0.088646)
		(layer "In11.Cu")
		(net "M_D_CPU0_SB_DQ<24>")
	)
	(segment
		(start 310.428894 -206.125826)
		(end 307.635148 -206.125826)
		(width 0.18288)
		(layer "In11.Cu")
		(net "M_D_CPU0_SB_DQ<24>")
	)
	(segment
		(start 333.932022 -228.139752)
		(end 333.923132 -228.134672)
		(width 0.088646)
		(layer "In11.Cu")
		(net "M_D_CPU0_SB_DQ<24>")
	)
	(segment
		(start 265.154664 -204.542136)
		(end 264.729214 -204.116686)
		(width 0.18288)
		(layer "In11.Cu")
		(net "M_D_CPU0_SB_DQ<24>")
	)
	(segment
		(start 267.941298 -204.735176)
		(end 267.941298 -205.24978)
		(width 0.18288)
		(layer "In11.Cu")
		(net "M_D_CPU0_SB_DQ<24>")
	)
	(segment
		(start 265.645138 -204.542136)
		(end 265.154664 -204.542136)
		(width 0.18288)
		(layer "In11.Cu")
		(net "M_D_CPU0_SB_DQ<24>")
	)
	(segment
		(start 273.725894 -203.662026)
		(end 273.040094 -204.347826)
		(width 0.18288)
		(layer "In11.Cu")
		(net "M_D_CPU0_SB_DQ<24>")
	)
	(segment
		(start 265.838178 -205.24978)
		(end 265.838178 -204.735176)
		(width 0.18288)
		(layer "In11.Cu")
		(net "M_D_CPU0_SB_DQ<24>")
	)
	(segment
		(start 269.518384 -204.542136)
		(end 268.134338 -204.542136)
		(width 0.18288)
		(layer "In11.Cu")
		(net "M_D_CPU0_SB_DQ<24>")
	)
	(segment
		(start 330.313538 -227.327714)
		(end 329.747118 -227.327714)
		(width 0.18288)
		(layer "In11.Cu")
		(net "M_D_CPU0_SB_DQ<24>")
	)
	(segment
		(start 343.799922 -230.5812)
		(end 343.791032 -230.57612)
		(width 0.088646)
		(layer "In11.Cu")
		(net "M_D_CPU0_SB_DQ<24>")
	)
	(segment
		(start 341.066882 -229.762304)
		(end 341.05215 -229.77094)
		(width 0.088646)
		(layer "In11.Cu")
		(net "M_D_CPU0_SB_DQ<24>")
	)
	(segment
		(start 335.802478 -229.762304)
		(end 335.802732 -229.762304)
		(width 0.088646)
		(layer "In11.Cu")
		(net "M_D_CPU0_SB_DQ<24>")
	)
	(segment
		(start 270.457676 -204.347826)
		(end 269.712694 -204.347826)
		(width 0.18288)
		(layer "In11.Cu")
		(net "M_D_CPU0_SB_DQ<24>")
	)
	(segment
		(start 334.862424 -229.762304)
		(end 334.862678 -229.762304)
		(width 0.088646)
		(layer "In11.Cu")
		(net "M_D_CPU0_SB_DQ<24>")
	)
	(segment
		(start 281.542236 -203.56195)
		(end 281.413966 -203.69022)
		(width 0.18288)
		(layer "In11.Cu")
		(net "M_D_CPU0_SB_DQ<24>")
	)
	(segment
		(start 299.798486 -204.542644)
		(end 298.008548 -204.542644)
		(width 0.18288)
		(layer "In11.Cu")
		(net "M_D_CPU0_SB_DQ<24>")
	)
	(segment
		(start 300.0629 -204.27823)
		(end 299.798486 -204.542644)
		(width 0.18288)
		(layer "In11.Cu")
		(net "M_D_CPU0_SB_DQ<24>")
	)
	(segment
		(start 307.635148 -206.125826)
		(end 305.089814 -203.580492)
		(width 0.18288)
		(layer "In11.Cu")
		(net "M_D_CPU0_SB_DQ<24>")
	)
	(segment
		(start 289.180524 -204.867256)
		(end 288.737294 -204.424026)
		(width 0.18288)
		(layer "In11.Cu")
		(net "M_D_CPU0_SB_DQ<24>")
	)
	(segment
		(start 343.978484 -230.922576)
		(end 343.978484 -230.900478)
		(width 0.088646)
		(layer "In11.Cu")
		(net "M_D_CPU0_SB_DQ<24>")
	)
	(segment
		(start 273.040094 -204.347826)
		(end 271.544796 -204.347826)
		(width 0.18288)
		(layer "In11.Cu")
		(net "M_D_CPU0_SB_DQ<24>")
	)
	(segment
		(start 285.000192 -204.54239)
		(end 283.140658 -204.54239)
		(width 0.18288)
		(layer "In11.Cu")
		(net "M_D_CPU0_SB_DQ<24>")
	)
	(segment
		(start 311.267094 -206.964026)
		(end 310.428894 -206.125826)
		(width 0.18288)
		(layer "In11.Cu")
		(net "M_D_CPU0_SB_DQ<24>")
	)
	(segment
		(start 281.413966 -203.69022)
		(end 279.47366 -203.69022)
		(width 0.18288)
		(layer "In11.Cu")
		(net "M_D_CPU0_SB_DQ<24>")
	)
	(segment
		(start 329.747118 -227.327714)
		(end 319.883282 -217.463878)
		(width 0.18288)
		(layer "In11.Cu")
		(net "M_D_CPU0_SB_DQ<24>")
	)
	(segment
		(start 267.240258 -205.24978)
		(end 267.240258 -204.735176)
		(width 0.18288)
		(layer "In11.Cu")
		(net "M_D_CPU0_SB_DQ<24>")
	)
	(segment
		(start 305.089814 -203.580492)
		(end 303.068228 -203.580492)
		(width 0.18288)
		(layer "In11.Cu")
		(net "M_D_CPU0_SB_DQ<24>")
	)
	(segment
		(start 267.047218 -204.542136)
		(end 266.732258 -204.542136)
		(width 0.18288)
		(layer "In11.Cu")
		(net "M_D_CPU0_SB_DQ<24>")
	)
	(segment
		(start 266.732258 -204.542136)
		(end 266.539218 -204.735176)
		(width 0.18288)
		(layer "In11.Cu")
		(net "M_D_CPU0_SB_DQ<24>")
	)
	(segment
		(start 279.171654 -203.992226)
		(end 277.434294 -203.992226)
		(width 0.18288)
		(layer "In11.Cu")
		(net "M_D_CPU0_SB_DQ<24>")
	)
	(segment
		(start 285.118556 -204.424026)
		(end 285.000192 -204.54239)
		(width 0.18288)
		(layer "In11.Cu")
		(net "M_D_CPU0_SB_DQ<24>")
	)
	(segment
		(start 312.382408 -207.32623)
		(end 312.020204 -206.964026)
		(width 0.18288)
		(layer "In11.Cu")
		(net "M_D_CPU0_SB_DQ<24>")
	)
	(segment
		(start 270.650716 -204.540866)
		(end 270.457676 -204.347826)
		(width 0.18288)
		(layer "In11.Cu")
		(net "M_D_CPU0_SB_DQ<24>")
	)
	(segment
		(start 344.730832 -232.204006)
		(end 344.724736 -232.20045)
		(width 0.088646)
		(layer "In11.Cu")
		(net "M_D_CPU0_SB_DQ<24>")
	)
	(segment
		(start 270.843756 -205.28661)
		(end 270.650716 -205.09357)
		(width 0.18288)
		(layer "In11.Cu")
		(net "M_D_CPU0_SB_DQ<24>")
	)
	(segment
		(start 271.544796 -204.347826)
		(end 271.351756 -204.540866)
		(width 0.18288)
		(layer "In11.Cu")
		(net "M_D_CPU0_SB_DQ<24>")
	)
	(segment
		(start 312.382408 -207.638396)
		(end 312.382408 -207.32623)
		(width 0.18288)
		(layer "In11.Cu")
		(net "M_D_CPU0_SB_DQ<24>")
	)
	(segment
		(start 336.367882 -229.762304)
		(end 336.35315 -229.77094)
		(width 0.088646)
		(layer "In11.Cu")
		(net "M_D_CPU0_SB_DQ<24>")
	)
	(segment
		(start 266.346178 -205.44282)
		(end 266.031218 -205.44282)
		(width 0.18288)
		(layer "In11.Cu")
		(net "M_D_CPU0_SB_DQ<24>")
	)
	(segment
		(start 271.158716 -205.28661)
		(end 270.843756 -205.28661)
		(width 0.18288)
		(layer "In11.Cu")
		(net "M_D_CPU0_SB_DQ<24>")
	)
	(segment
		(start 269.712694 -204.347826)
		(end 269.518384 -204.542136)
		(width 0.18288)
		(layer "In11.Cu")
		(net "M_D_CPU0_SB_DQ<24>")
	)
	(segment
		(start 343.329768 -229.767384)
		(end 343.320878 -229.762304)
		(width 0.088646)
		(layer "In11.Cu")
		(net "M_D_CPU0_SB_DQ<24>")
	)
	(segment
		(start 265.838178 -204.735176)
		(end 265.645138 -204.542136)
		(width 0.18288)
		(layer "In11.Cu")
		(net "M_D_CPU0_SB_DQ<24>")
	)
	(segment
		(start 271.351756 -205.09357)
		(end 271.158716 -205.28661)
		(width 0.18288)
		(layer "In11.Cu")
		(net "M_D_CPU0_SB_DQ<24>")
	)
	(segment
		(start 312.020204 -206.964026)
		(end 311.267094 -206.964026)
		(width 0.18288)
		(layer "In11.Cu")
		(net "M_D_CPU0_SB_DQ<24>")
	)
	(segment
		(start 266.539218 -204.735176)
		(end 266.539218 -205.24978)
		(width 0.18288)
		(layer "In11.Cu")
		(net "M_D_CPU0_SB_DQ<24>")
	)
	(segment
		(start 277.434294 -203.992226)
		(end 277.104094 -203.662026)
		(width 0.18288)
		(layer "In11.Cu")
		(net "M_D_CPU0_SB_DQ<24>")
	)
	(segment
		(start 297.155108 -203.689204)
		(end 293.749984 -203.689204)
		(width 0.18288)
		(layer "In11.Cu")
		(net "M_D_CPU0_SB_DQ<24>")
	)
	(segment
		(start 319.883282 -214.573104)
		(end 314.762896 -209.452718)
		(width 0.18288)
		(layer "In11.Cu")
		(net "M_D_CPU0_SB_DQ<24>")
	)
	(segment
		(start 339.187282 -229.762304)
		(end 339.176868 -229.7684)
		(width 0.088646)
		(layer "In11.Cu")
		(net "M_D_CPU0_SB_DQ<24>")
	)
	(segment
		(start 279.47366 -203.69022)
		(end 279.171654 -203.992226)
		(width 0.18288)
		(layer "In11.Cu")
		(net "M_D_CPU0_SB_DQ<24>")
	)
	(segment
		(start 293.749984 -203.689204)
		(end 293.040562 -204.398626)
		(width 0.18288)
		(layer "In11.Cu")
		(net "M_D_CPU0_SB_DQ<24>")
	)
	(arc
		(start 342.381078 -229.762304)
		(mid 342.19388 -229.712161)
		(end 342.006682 -229.762304)
		(width 0.088646)
		(layer "In11.Cu")
		(net "M_D_CPU0_SB_DQ<24>")
	)
	(arc
		(start 344.44813 -231.714548)
		(mid 344.400451 -231.531648)
		(end 344.269568 -231.39527)
		(width 0.088646)
		(layer "In11.Cu")
		(net "M_D_CPU0_SB_DQ<24>")
	)
	(arc
		(start 335.802732 -229.762304)
		(mid 335.615534 -229.712161)
		(end 335.428336 -229.762304)
		(width 0.088646)
		(layer "In11.Cu")
		(net "M_D_CPU0_SB_DQ<24>")
	)
	(arc
		(start 344.260678 -231.39019)
		(mid 344.059396 -231.192703)
		(end 343.978484 -230.922576)
		(width 0.088646)
		(layer "In11.Cu")
		(net "M_D_CPU0_SB_DQ<24>")
	)
	(arc
		(start 343.784936 -230.572564)
		(mid 343.582349 -230.366213)
		(end 343.50833 -230.086662)
		(width 0.088646)
		(layer "In11.Cu")
		(net "M_D_CPU0_SB_DQ<24>")
	)
	(arc
		(start 344.724736 -232.20045)
		(mid 344.522149 -231.994099)
		(end 344.44813 -231.714548)
		(width 0.088646)
		(layer "In11.Cu")
		(net "M_D_CPU0_SB_DQ<24>")
	)
	(arc
		(start 334.110584 -228.45903)
		(mid 334.062905 -228.27613)
		(end 333.932022 -228.139752)
		(width 0.088646)
		(layer "In11.Cu")
		(net "M_D_CPU0_SB_DQ<24>")
	)
	(arc
		(start 338.237322 -229.7684)
		(mid 337.95889 -229.838246)
		(end 337.682078 -229.762304)
		(width 0.088646)
		(layer "In11.Cu")
		(net "M_D_CPU0_SB_DQ<24>")
	)
	(arc
		(start 345.296236 -232.204006)
		(mid 345.022037 -232.279841)
		(end 344.745564 -232.212642)
		(width 0.088646)
		(layer "In11.Cu")
		(net "M_D_CPU0_SB_DQ<24>")
	)
	(arc
		(start 332.983332 -228.134672)
		(mid 332.796134 -228.084529)
		(end 332.608936 -228.134672)
		(width 0.088646)
		(layer "In11.Cu")
		(net "M_D_CPU0_SB_DQ<24>")
	)
	(arc
		(start 336.742278 -229.762304)
		(mid 336.55508 -229.712161)
		(end 336.367882 -229.762304)
		(width 0.088646)
		(layer "In11.Cu")
		(net "M_D_CPU0_SB_DQ<24>")
	)
	(arc
		(start 335.428336 -229.762304)
		(mid 335.14538 -229.838207)
		(end 334.862424 -229.762304)
		(width 0.088646)
		(layer "In11.Cu")
		(net "M_D_CPU0_SB_DQ<24>")
	)
	(arc
		(start 340.11235 -229.77094)
		(mid 339.835875 -229.83826)
		(end 339.561678 -229.762304)
		(width 0.088646)
		(layer "In11.Cu")
		(net "M_D_CPU0_SB_DQ<24>")
	)
	(arc
		(start 346.235782 -232.204006)
		(mid 345.959223 -232.279749)
		(end 345.681046 -232.210102)
		(width 0.088646)
		(layer "In11.Cu")
		(net "M_D_CPU0_SB_DQ<24>")
	)
	(arc
		(start 339.561678 -229.762304)
		(mid 339.37448 -229.712161)
		(end 339.187282 -229.762304)
		(width 0.088646)
		(layer "In11.Cu")
		(net "M_D_CPU0_SB_DQ<24>")
	)
	(arc
		(start 343.320878 -229.762304)
		(mid 343.13368 -229.712161)
		(end 342.946482 -229.762304)
		(width 0.088646)
		(layer "In11.Cu")
		(net "M_D_CPU0_SB_DQ<24>")
	)
	(arc
		(start 332.608936 -228.134672)
		(mid 332.472463 -228.191306)
		(end 332.32598 -228.210618)
		(width 0.088646)
		(layer "In11.Cu")
		(net "M_D_CPU0_SB_DQ<24>")
	)
	(arc
		(start 339.176868 -229.7684)
		(mid 338.89869 -229.838123)
		(end 338.622132 -229.762304)
		(width 0.088646)
		(layer "In11.Cu")
		(net "M_D_CPU0_SB_DQ<24>")
	)
	(arc
		(start 346.89288 -231.714548)
		(mid 346.578598 -231.978432)
		(end 346.235782 -232.204006)
		(width 0.088646)
		(layer "In11.Cu")
		(net "M_D_CPU0_SB_DQ<24>")
	)
	(arc
		(start 334.58023 -229.26421)
		(mid 334.52796 -229.081845)
		(end 334.393032 -228.948488)
		(width 0.088646)
		(layer "In11.Cu")
		(net "M_D_CPU0_SB_DQ<24>")
	)
	(arc
		(start 343.50833 -230.086662)
		(mid 343.460651 -229.903762)
		(end 343.329768 -229.767384)
		(width 0.088646)
		(layer "In11.Cu")
		(net "M_D_CPU0_SB_DQ<24>")
	)
	(arc
		(start 345.670632 -232.204006)
		(mid 345.483434 -232.153863)
		(end 345.296236 -232.204006)
		(width 0.088646)
		(layer "In11.Cu")
		(net "M_D_CPU0_SB_DQ<24>")
	)
	(arc
		(start 334.393032 -228.948488)
		(mid 334.188697 -228.745883)
		(end 334.110584 -228.468936)
		(width 0.088646)
		(layer "In11.Cu")
		(net "M_D_CPU0_SB_DQ<24>")
	)
	(arc
		(start 340.501478 -229.762304)
		(mid 340.31428 -229.712161)
		(end 340.127082 -229.762304)
		(width 0.088646)
		(layer "In11.Cu")
		(net "M_D_CPU0_SB_DQ<24>")
	)
	(arc
		(start 336.35315 -229.77094)
		(mid 336.076675 -229.83826)
		(end 335.802478 -229.762304)
		(width 0.088646)
		(layer "In11.Cu")
		(net "M_D_CPU0_SB_DQ<24>")
	)
	(arc
		(start 341.99195 -229.77094)
		(mid 341.715475 -229.83826)
		(end 341.441278 -229.762304)
		(width 0.088646)
		(layer "In11.Cu")
		(net "M_D_CPU0_SB_DQ<24>")
	)
	(arc
		(start 341.05215 -229.77094)
		(mid 340.775675 -229.83826)
		(end 340.501478 -229.762304)
		(width 0.088646)
		(layer "In11.Cu")
		(net "M_D_CPU0_SB_DQ<24>")
	)
	(arc
		(start 338.622132 -229.762304)
		(mid 338.434934 -229.712161)
		(end 338.247736 -229.762304)
		(width 0.088646)
		(layer "In11.Cu")
		(net "M_D_CPU0_SB_DQ<24>")
	)
	(arc
		(start 334.862678 -229.762304)
		(mid 334.658343 -229.559699)
		(end 334.58023 -229.282752)
		(width 0.088646)
		(layer "In11.Cu")
		(net "M_D_CPU0_SB_DQ<24>")
	)
	(arc
		(start 337.682078 -229.762304)
		(mid 337.49488 -229.712161)
		(end 337.307682 -229.762304)
		(width 0.088646)
		(layer "In11.Cu")
		(net "M_D_CPU0_SB_DQ<24>")
	)
	(arc
		(start 333.923132 -228.134672)
		(mid 333.735934 -228.084529)
		(end 333.548736 -228.134672)
		(width 0.088646)
		(layer "In11.Cu")
		(net "M_D_CPU0_SB_DQ<24>")
	)
	(arc
		(start 342.946482 -229.762304)
		(mid 342.66378 -229.83808)
		(end 342.381078 -229.762304)
		(width 0.088646)
		(layer "In11.Cu")
		(net "M_D_CPU0_SB_DQ<24>")
	)
	(arc
		(start 341.441278 -229.762304)
		(mid 341.25408 -229.712161)
		(end 341.066882 -229.762304)
		(width 0.088646)
		(layer "In11.Cu")
		(net "M_D_CPU0_SB_DQ<24>")
	)
	(arc
		(start 343.978484 -230.900478)
		(mid 343.930805 -230.717578)
		(end 343.799922 -230.5812)
		(width 0.088646)
		(layer "In11.Cu")
		(net "M_D_CPU0_SB_DQ<24>")
	)
	(arc
		(start 333.548736 -228.134672)
		(mid 333.274507 -228.210597)
		(end 332.998064 -228.143308)
		(width 0.088646)
		(layer "In11.Cu")
		(net "M_D_CPU0_SB_DQ<24>")
	)
	(arc
		(start 337.29295 -229.77094)
		(mid 337.016475 -229.83826)
		(end 336.742278 -229.762304)
		(width 0.088646)
		(layer "In11.Cu")
		(net "M_D_CPU0_SB_DQ<24>")
	)
	(segment
		(start 266.90828 -204.96657)
		(end 266.700762 -205.174088)
		(width 0.20066)
		(layer "F.Cu")
		(net "M_D_CPU0_SB_DQ<23>")
	)
	(segment
		(start 262.003794 -205.263242)
		(end 262.003794 -205.092554)
		(width 0.20066)
		(layer "F.Cu")
		(net "M_D_CPU0_SB_DQ<23>")
	)
	(segment
		(start 262.752332 -205.391512)
		(end 262.514334 -205.391512)
		(width 0.101854)
		(layer "F.Cu")
		(net "M_D_CPU0_SB_DQ<23>")
	)
	(segment
		(start 267.724382 -204.96657)
		(end 266.90828 -204.96657)
		(width 0.20066)
		(layer "F.Cu")
		(net "M_D_CPU0_SB_DQ<23>")
	)
	(segment
		(start 266.25423 -205.174088)
		(end 266.042394 -204.962252)
		(width 0.20066)
		(layer "F.Cu")
		(net "M_D_CPU0_SB_DQ<23>")
	)
	(segment
		(start 265.64717 -204.962252)
		(end 265.518646 -205.090776)
		(width 0.20066)
		(layer "F.Cu")
		(net "M_D_CPU0_SB_DQ<23>")
	)
	(segment
		(start 344.54338 -231.436418)
		(end 344.543634 -231.436164)
		(width 0.20066)
		(layer "F.Cu")
		(net "M_D_CPU0_SB_DQ<23>")
	)
	(segment
		(start 268.829282 -204.96657)
		(end 267.724382 -204.96657)
		(width 0.20066)
		(layer "F.Cu")
		(net "M_D_CPU0_SB_DQ<23>")
	)
	(segment
		(start 262.50011 -205.405736)
		(end 262.146288 -205.405736)
		(width 0.20066)
		(layer "F.Cu")
		(net "M_D_CPU0_SB_DQ<23>")
	)
	(segment
		(start 262.146288 -205.405736)
		(end 262.003794 -205.263242)
		(width 0.20066)
		(layer "F.Cu")
		(net "M_D_CPU0_SB_DQ<23>")
	)
	(segment
		(start 266.042394 -204.962252)
		(end 265.64717 -204.962252)
		(width 0.20066)
		(layer "F.Cu")
		(net "M_D_CPU0_SB_DQ<23>")
	)
	(segment
		(start 262.514334 -205.391512)
		(end 262.50011 -205.405736)
		(width 0.101854)
		(layer "F.Cu")
		(net "M_D_CPU0_SB_DQ<23>")
	)
	(segment
		(start 262.003794 -205.092554)
		(end 261.87781 -204.96657)
		(width 0.20066)
		(layer "F.Cu")
		(net "M_D_CPU0_SB_DQ<23>")
	)
	(segment
		(start 265.369548 -205.391512)
		(end 264.825226 -205.391512)
		(width 0.20066)
		(layer "F.Cu")
		(net "M_D_CPU0_SB_DQ<23>")
	)
	(segment
		(start 265.518646 -205.242414)
		(end 265.369548 -205.391512)
		(width 0.20066)
		(layer "F.Cu")
		(net "M_D_CPU0_SB_DQ<23>")
	)
	(segment
		(start 261.87781 -204.96657)
		(end 260.180582 -204.96657)
		(width 0.20066)
		(layer "F.Cu")
		(net "M_D_CPU0_SB_DQ<23>")
	)
	(segment
		(start 265.518646 -205.090776)
		(end 265.518646 -205.242414)
		(width 0.20066)
		(layer "F.Cu")
		(net "M_D_CPU0_SB_DQ<23>")
	)
	(segment
		(start 266.700762 -205.174088)
		(end 266.25423 -205.174088)
		(width 0.20066)
		(layer "F.Cu")
		(net "M_D_CPU0_SB_DQ<23>")
	)
	(segment
		(start 264.825226 -205.391512)
		(end 262.752332 -205.391512)
		(width 0.1016)
		(layer "F.Cu")
		(net "M_D_CPU0_SB_DQ<23>")
	)
	(segment
		(start 344.543634 -231.436164)
		(end 344.543634 -230.900478)
		(width 0.20066)
		(layer "F.Cu")
		(net "M_D_CPU0_SB_DQ<23>")
	)
	(segment
		(start 283.23794 -204.126592)
		(end 282.483306 -204.126592)
		(width 0.18288)
		(layer "In6.Cu")
		(net "M_D_CPU0_SB_DQ<23>")
	)
	(segment
		(start 274.93214 -204.380846)
		(end 274.77212 -204.540866)
		(width 0.18288)
		(layer "In6.Cu")
		(net "M_D_CPU0_SB_DQ<23>")
	)
	(segment
		(start 283.67228 -203.692252)
		(end 283.23794 -204.126592)
		(width 0.18288)
		(layer "In6.Cu")
		(net "M_D_CPU0_SB_DQ<23>")
	)
	(segment
		(start 316.758828 -213.375494)
		(end 315.651388 -210.702652)
		(width 0.18288)
		(layer "In6.Cu")
		(net "M_D_CPU0_SB_DQ<23>")
	)
	(segment
		(start 324.90283 -224.197164)
		(end 324.90283 -221.519496)
		(width 0.18288)
		(layer "In6.Cu")
		(net "M_D_CPU0_SB_DQ<23>")
	)
	(segment
		(start 335.898236 -229.597204)
		(end 335.887822 -229.591108)
		(width 0.088646)
		(layer "In6.Cu")
		(net "M_D_CPU0_SB_DQ<23>")
	)
	(segment
		(start 311.71896 -206.945992)
		(end 310.96966 -206.945992)
		(width 0.18288)
		(layer "In6.Cu")
		(net "M_D_CPU0_SB_DQ<23>")
	)
	(segment
		(start 300.726602 -203.86548)
		(end 299.35678 -203.86548)
		(width 0.18288)
		(layer "In6.Cu")
		(net "M_D_CPU0_SB_DQ<23>")
	)
	(segment
		(start 270.661892 -203.601066)
		(end 270.479012 -203.783946)
		(width 0.18288)
		(layer "In6.Cu")
		(net "M_D_CPU0_SB_DQ<23>")
	)
	(segment
		(start 274.77212 -204.540866)
		(end 272.98396 -204.540866)
		(width 0.18288)
		(layer "In6.Cu")
		(net "M_D_CPU0_SB_DQ<23>")
	)
	(segment
		(start 275.09216 -204.012038)
		(end 274.93214 -204.172058)
		(width 0.18288)
		(layer "In6.Cu")
		(net "M_D_CPU0_SB_DQ<23>")
	)
	(segment
		(start 310.66232 -207.253332)
		(end 309.278528 -207.253332)
		(width 0.18288)
		(layer "In6.Cu")
		(net "M_D_CPU0_SB_DQ<23>")
	)
	(segment
		(start 289.21456 -204.825092)
		(end 288.415984 -204.026516)
		(width 0.18288)
		(layer "In6.Cu")
		(net "M_D_CPU0_SB_DQ<23>")
	)
	(segment
		(start 270.479012 -204.16012)
		(end 270.296132 -204.343)
		(width 0.18288)
		(layer "In6.Cu")
		(net "M_D_CPU0_SB_DQ<23>")
	)
	(segment
		(start 281.749246 -204.860652)
		(end 281.20086 -204.860652)
		(width 0.18288)
		(layer "In6.Cu")
		(net "M_D_CPU0_SB_DQ<23>")
	)
	(segment
		(start 342.006682 -230.41102)
		(end 341.99195 -230.402384)
		(width 0.088646)
		(layer "In6.Cu")
		(net "M_D_CPU0_SB_DQ<23>")
	)
	(segment
		(start 271.169892 -204.16012)
		(end 271.169892 -203.783946)
		(width 0.18288)
		(layer "In6.Cu")
		(net "M_D_CPU0_SB_DQ<23>")
	)
	(segment
		(start 327.06183 -226.356164)
		(end 324.90283 -224.197164)
		(width 0.18288)
		(layer "In6.Cu")
		(net "M_D_CPU0_SB_DQ<23>")
	)
	(segment
		(start 291.40912 -204.825092)
		(end 289.21456 -204.825092)
		(width 0.18288)
		(layer "In6.Cu")
		(net "M_D_CPU0_SB_DQ<23>")
	)
	(segment
		(start 314.519056 -209.57032)
		(end 314.343288 -209.57032)
		(width 0.18288)
		(layer "In6.Cu")
		(net "M_D_CPU0_SB_DQ<23>")
	)
	(segment
		(start 280.881074 -204.540866)
		(end 275.78558 -204.540866)
		(width 0.18288)
		(layer "In6.Cu")
		(net "M_D_CPU0_SB_DQ<23>")
	)
	(segment
		(start 282.483306 -204.126592)
		(end 281.749246 -204.860652)
		(width 0.18288)
		(layer "In6.Cu")
		(net "M_D_CPU0_SB_DQ<23>")
	)
	(segment
		(start 305.702462 -205.73746)
		(end 305.519582 -205.55458)
		(width 0.18288)
		(layer "In6.Cu")
		(net "M_D_CPU0_SB_DQ<23>")
	)
	(segment
		(start 337.227164 -229.588568)
		(end 337.212432 -229.597204)
		(width 0.088646)
		(layer "In6.Cu")
		(net "M_D_CPU0_SB_DQ<23>")
	)
	(segment
		(start 272.98396 -204.540866)
		(end 272.786094 -204.343)
		(width 0.18288)
		(layer "In6.Cu")
		(net "M_D_CPU0_SB_DQ<23>")
	)
	(segment
		(start 297.493944 -204.538834)
		(end 291.695378 -204.538834)
		(width 0.18288)
		(layer "In6.Cu")
		(net "M_D_CPU0_SB_DQ<23>")
	)
	(segment
		(start 305.011582 -206.196946)
		(end 304.828702 -206.379826)
		(width 0.18288)
		(layer "In6.Cu")
		(net "M_D_CPU0_SB_DQ<23>")
	)
	(segment
		(start 270.296132 -204.343)
		(end 269.452852 -204.343)
		(width 0.18288)
		(layer "In6.Cu")
		(net "M_D_CPU0_SB_DQ<23>")
	)
	(segment
		(start 275.62556 -204.172058)
		(end 275.46554 -204.012038)
		(width 0.18288)
		(layer "In6.Cu")
		(net "M_D_CPU0_SB_DQ<23>")
	)
	(segment
		(start 334.770984 -229.281482)
		(end 334.770984 -229.272846)
		(width 0.088646)
		(layer "In6.Cu")
		(net "M_D_CPU0_SB_DQ<23>")
	)
	(segment
		(start 284.207966 -203.692252)
		(end 283.67228 -203.692252)
		(width 0.18288)
		(layer "In6.Cu")
		(net "M_D_CPU0_SB_DQ<23>")
	)
	(segment
		(start 298.828714 -203.695046)
		(end 298.59478 -203.92898)
		(width 0.18288)
		(layer "In6.Cu")
		(net "M_D_CPU0_SB_DQ<23>")
	)
	(segment
		(start 334.770984 -229.272846)
		(end 334.77073 -229.26294)
		(width 0.088646)
		(layer "In6.Cu")
		(net "M_D_CPU0_SB_DQ<23>")
	)
	(segment
		(start 340.127082 -230.41102)
		(end 340.11235 -230.402384)
		(width 0.088646)
		(layer "In6.Cu")
		(net "M_D_CPU0_SB_DQ<23>")
	)
	(segment
		(start 305.702462 -206.196946)
		(end 305.702462 -205.73746)
		(width 0.18288)
		(layer "In6.Cu")
		(net "M_D_CPU0_SB_DQ<23>")
	)
	(segment
		(start 303.17186 -205.447392)
		(end 302.308514 -205.447392)
		(width 0.18288)
		(layer "In6.Cu")
		(net "M_D_CPU0_SB_DQ<23>")
	)
	(segment
		(start 275.46554 -204.012038)
		(end 275.09216 -204.012038)
		(width 0.18288)
		(layer "In6.Cu")
		(net "M_D_CPU0_SB_DQ<23>")
	)
	(segment
		(start 304.104294 -206.379826)
		(end 303.17186 -205.447392)
		(width 0.18288)
		(layer "In6.Cu")
		(net "M_D_CPU0_SB_DQ<23>")
	)
	(segment
		(start 330.707238 -226.356164)
		(end 330.41971 -226.356164)
		(width 0.088646)
		(layer "In6.Cu")
		(net "M_D_CPU0_SB_DQ<23>")
	)
	(segment
		(start 315.651388 -210.702652)
		(end 314.519056 -209.57032)
		(width 0.18288)
		(layer "In6.Cu")
		(net "M_D_CPU0_SB_DQ<23>")
	)
	(segment
		(start 305.885342 -206.379826)
		(end 305.702462 -206.196946)
		(width 0.18288)
		(layer "In6.Cu")
		(net "M_D_CPU0_SB_DQ<23>")
	)
	(segment
		(start 270.987012 -203.601066)
		(end 270.661892 -203.601066)
		(width 0.18288)
		(layer "In6.Cu")
		(net "M_D_CPU0_SB_DQ<23>")
	)
	(segment
		(start 272.786094 -204.343)
		(end 271.352772 -204.343)
		(width 0.18288)
		(layer "In6.Cu")
		(net "M_D_CPU0_SB_DQ<23>")
	)
	(segment
		(start 314.343288 -209.57032)
		(end 311.71896 -206.945992)
		(width 0.18288)
		(layer "In6.Cu")
		(net "M_D_CPU0_SB_DQ<23>")
	)
	(segment
		(start 307.025294 -206.176626)
		(end 306.822094 -206.379826)
		(width 0.18288)
		(layer "In6.Cu")
		(net "M_D_CPU0_SB_DQ<23>")
	)
	(segment
		(start 298.103798 -203.92898)
		(end 297.493944 -204.538834)
		(width 0.18288)
		(layer "In6.Cu")
		(net "M_D_CPU0_SB_DQ<23>")
	)
	(segment
		(start 281.20086 -204.860652)
		(end 280.881074 -204.540866)
		(width 0.18288)
		(layer "In6.Cu")
		(net "M_D_CPU0_SB_DQ<23>")
	)
	(segment
		(start 332.42123 -228.459284)
		(end 332.42123 -228.070156)
		(width 0.088646)
		(layer "In6.Cu")
		(net "M_D_CPU0_SB_DQ<23>")
	)
	(segment
		(start 271.169892 -203.783946)
		(end 270.987012 -203.601066)
		(width 0.18288)
		(layer "In6.Cu")
		(net "M_D_CPU0_SB_DQ<23>")
	)
	(segment
		(start 310.96966 -206.945992)
		(end 310.66232 -207.253332)
		(width 0.18288)
		(layer "In6.Cu")
		(net "M_D_CPU0_SB_DQ<23>")
	)
	(segment
		(start 270.479012 -203.783946)
		(end 270.479012 -204.16012)
		(width 0.18288)
		(layer "In6.Cu")
		(net "M_D_CPU0_SB_DQ<23>")
	)
	(segment
		(start 291.695378 -204.538834)
		(end 291.40912 -204.825092)
		(width 0.18288)
		(layer "In6.Cu")
		(net "M_D_CPU0_SB_DQ<23>")
	)
	(segment
		(start 271.352772 -204.343)
		(end 271.169892 -204.16012)
		(width 0.18288)
		(layer "In6.Cu")
		(net "M_D_CPU0_SB_DQ<23>")
	)
	(segment
		(start 284.54223 -204.026516)
		(end 284.207966 -203.692252)
		(width 0.18288)
		(layer "In6.Cu")
		(net "M_D_CPU0_SB_DQ<23>")
	)
	(segment
		(start 332.42123 -228.070156)
		(end 330.707238 -226.356164)
		(width 0.088646)
		(layer "In6.Cu")
		(net "M_D_CPU0_SB_DQ<23>")
	)
	(segment
		(start 275.62556 -204.380846)
		(end 275.62556 -204.172058)
		(width 0.18288)
		(layer "In6.Cu")
		(net "M_D_CPU0_SB_DQ<23>")
	)
	(segment
		(start 306.822094 -206.379826)
		(end 305.885342 -206.379826)
		(width 0.18288)
		(layer "In6.Cu")
		(net "M_D_CPU0_SB_DQ<23>")
	)
	(segment
		(start 288.415984 -204.026516)
		(end 284.54223 -204.026516)
		(width 0.18288)
		(layer "In6.Cu")
		(net "M_D_CPU0_SB_DQ<23>")
	)
	(segment
		(start 332.421484 -228.45903)
		(end 332.42123 -228.459284)
		(width 0.088646)
		(layer "In6.Cu")
		(net "M_D_CPU0_SB_DQ<23>")
	)
	(segment
		(start 274.93214 -204.172058)
		(end 274.93214 -204.380846)
		(width 0.18288)
		(layer "In6.Cu")
		(net "M_D_CPU0_SB_DQ<23>")
	)
	(segment
		(start 299.35678 -203.86548)
		(end 299.186346 -203.695046)
		(width 0.18288)
		(layer "In6.Cu")
		(net "M_D_CPU0_SB_DQ<23>")
	)
	(segment
		(start 298.59478 -203.92898)
		(end 298.103798 -203.92898)
		(width 0.18288)
		(layer "In6.Cu")
		(net "M_D_CPU0_SB_DQ<23>")
	)
	(segment
		(start 275.78558 -204.540866)
		(end 275.62556 -204.380846)
		(width 0.18288)
		(layer "In6.Cu")
		(net "M_D_CPU0_SB_DQ<23>")
	)
	(segment
		(start 299.186346 -203.695046)
		(end 298.828714 -203.695046)
		(width 0.18288)
		(layer "In6.Cu")
		(net "M_D_CPU0_SB_DQ<23>")
	)
	(segment
		(start 341.066882 -230.41102)
		(end 341.05215 -230.402384)
		(width 0.088646)
		(layer "In6.Cu")
		(net "M_D_CPU0_SB_DQ<23>")
	)
	(segment
		(start 339.000084 -230.095298)
		(end 339.000084 -230.076756)
		(width 0.088646)
		(layer "In6.Cu")
		(net "M_D_CPU0_SB_DQ<23>")
	)
	(segment
		(start 333.548736 -228.783642)
		(end 333.548736 -228.783388)
		(width 0.088646)
		(layer "In6.Cu")
		(net "M_D_CPU0_SB_DQ<23>")
	)
	(segment
		(start 304.828702 -206.379826)
		(end 304.104294 -206.379826)
		(width 0.18288)
		(layer "In6.Cu")
		(net "M_D_CPU0_SB_DQ<23>")
	)
	(segment
		(start 302.308514 -205.447392)
		(end 300.726602 -203.86548)
		(width 0.18288)
		(layer "In6.Cu")
		(net "M_D_CPU0_SB_DQ<23>")
	)
	(segment
		(start 305.011582 -205.73746)
		(end 305.011582 -206.196946)
		(width 0.18288)
		(layer "In6.Cu")
		(net "M_D_CPU0_SB_DQ<23>")
	)
	(segment
		(start 305.194462 -205.55458)
		(end 305.011582 -205.73746)
		(width 0.18288)
		(layer "In6.Cu")
		(net "M_D_CPU0_SB_DQ<23>")
	)
	(segment
		(start 342.946482 -230.41102)
		(end 342.93175 -230.402384)
		(width 0.088646)
		(layer "In6.Cu")
		(net "M_D_CPU0_SB_DQ<23>")
	)
	(segment
		(start 309.278528 -207.253332)
		(end 308.201822 -206.176626)
		(width 0.18288)
		(layer "In6.Cu")
		(net "M_D_CPU0_SB_DQ<23>")
	)
	(segment
		(start 308.201822 -206.176626)
		(end 307.025294 -206.176626)
		(width 0.18288)
		(layer "In6.Cu")
		(net "M_D_CPU0_SB_DQ<23>")
	)
	(segment
		(start 333.548736 -228.783388)
		(end 333.538322 -228.777292)
		(width 0.088646)
		(layer "In6.Cu")
		(net "M_D_CPU0_SB_DQ<23>")
	)
	(segment
		(start 324.90283 -221.519496)
		(end 316.758828 -213.375494)
		(width 0.18288)
		(layer "In6.Cu")
		(net "M_D_CPU0_SB_DQ<23>")
	)
	(segment
		(start 330.41971 -226.356164)
		(end 327.06183 -226.356164)
		(width 0.18288)
		(layer "In6.Cu")
		(net "M_D_CPU0_SB_DQ<23>")
	)
	(segment
		(start 269.452852 -204.343)
		(end 268.829282 -204.96657)
		(width 0.18288)
		(layer "In6.Cu")
		(net "M_D_CPU0_SB_DQ<23>")
	)
	(segment
		(start 305.519582 -205.55458)
		(end 305.194462 -205.55458)
		(width 0.18288)
		(layer "In6.Cu")
		(net "M_D_CPU0_SB_DQ<23>")
	)
	(segment
		(start 336.287364 -229.588568)
		(end 336.272632 -229.597204)
		(width 0.088646)
		(layer "In6.Cu")
		(net "M_D_CPU0_SB_DQ<23>")
	)
	(arc
		(start 337.777836 -229.597204)
		(mid 337.503637 -229.521369)
		(end 337.227164 -229.588568)
		(width 0.088646)
		(layer "In6.Cu")
		(net "M_D_CPU0_SB_DQ<23>")
	)
	(arc
		(start 333.923132 -228.783642)
		(mid 333.735934 -228.833785)
		(end 333.548736 -228.783642)
		(width 0.088646)
		(layer "In6.Cu")
		(net "M_D_CPU0_SB_DQ<23>")
	)
	(arc
		(start 342.93175 -230.402384)
		(mid 342.655275 -230.335064)
		(end 342.381078 -230.41102)
		(width 0.088646)
		(layer "In6.Cu")
		(net "M_D_CPU0_SB_DQ<23>")
	)
	(arc
		(start 340.11235 -230.402384)
		(mid 339.835875 -230.335064)
		(end 339.561678 -230.41102)
		(width 0.088646)
		(layer "In6.Cu")
		(net "M_D_CPU0_SB_DQ<23>")
	)
	(arc
		(start 338.152232 -229.597204)
		(mid 337.965034 -229.647347)
		(end 337.777836 -229.597204)
		(width 0.088646)
		(layer "In6.Cu")
		(net "M_D_CPU0_SB_DQ<23>")
	)
	(arc
		(start 336.272632 -229.597204)
		(mid 336.085434 -229.647347)
		(end 335.898236 -229.597204)
		(width 0.088646)
		(layer "In6.Cu")
		(net "M_D_CPU0_SB_DQ<23>")
	)
	(arc
		(start 341.05215 -230.402384)
		(mid 340.775675 -230.335064)
		(end 340.501478 -230.41102)
		(width 0.088646)
		(layer "In6.Cu")
		(net "M_D_CPU0_SB_DQ<23>")
	)
	(arc
		(start 333.538322 -228.777292)
		(mid 333.260144 -228.707569)
		(end 332.983586 -228.783388)
		(width 0.088646)
		(layer "In6.Cu")
		(net "M_D_CPU0_SB_DQ<23>")
	)
	(arc
		(start 337.212432 -229.597204)
		(mid 337.025234 -229.647347)
		(end 336.838036 -229.597204)
		(width 0.088646)
		(layer "In6.Cu")
		(net "M_D_CPU0_SB_DQ<23>")
	)
	(arc
		(start 334.77073 -229.26294)
		(mid 334.483874 -228.781262)
		(end 333.923132 -228.783642)
		(width 0.088646)
		(layer "In6.Cu")
		(net "M_D_CPU0_SB_DQ<23>")
	)
	(arc
		(start 340.501478 -230.41102)
		(mid 340.31428 -230.461163)
		(end 340.127082 -230.41102)
		(width 0.088646)
		(layer "In6.Cu")
		(net "M_D_CPU0_SB_DQ<23>")
	)
	(arc
		(start 342.381078 -230.41102)
		(mid 342.19388 -230.461163)
		(end 342.006682 -230.41102)
		(width 0.088646)
		(layer "In6.Cu")
		(net "M_D_CPU0_SB_DQ<23>")
	)
	(arc
		(start 339.561678 -230.41102)
		(mid 339.190955 -230.413112)
		(end 339.000084 -230.095298)
		(width 0.088646)
		(layer "In6.Cu")
		(net "M_D_CPU0_SB_DQ<23>")
	)
	(arc
		(start 344.543634 -230.900478)
		(mid 344.179193 -230.579386)
		(end 343.702894 -230.484426)
		(width 0.088646)
		(layer "In6.Cu")
		(net "M_D_CPU0_SB_DQ<23>")
	)
	(arc
		(start 343.076276 -230.45674)
		(mid 343.009261 -230.439894)
		(end 342.946482 -230.41102)
		(width 0.088646)
		(layer "In6.Cu")
		(net "M_D_CPU0_SB_DQ<23>")
	)
	(arc
		(start 341.441278 -230.41102)
		(mid 341.25408 -230.461163)
		(end 341.066882 -230.41102)
		(width 0.088646)
		(layer "In6.Cu")
		(net "M_D_CPU0_SB_DQ<23>")
	)
	(arc
		(start 336.838036 -229.597204)
		(mid 336.563837 -229.521369)
		(end 336.287364 -229.588568)
		(width 0.088646)
		(layer "In6.Cu")
		(net "M_D_CPU0_SB_DQ<23>")
	)
	(arc
		(start 341.99195 -230.402384)
		(mid 341.715475 -230.335064)
		(end 341.441278 -230.41102)
		(width 0.088646)
		(layer "In6.Cu")
		(net "M_D_CPU0_SB_DQ<23>")
	)
	(arc
		(start 332.983586 -228.783388)
		(mid 332.608889 -228.783507)
		(end 332.421484 -228.45903)
		(width 0.088646)
		(layer "In6.Cu")
		(net "M_D_CPU0_SB_DQ<23>")
	)
	(arc
		(start 339.000084 -230.076756)
		(mid 338.713209 -229.594671)
		(end 338.152232 -229.597204)
		(width 0.088646)
		(layer "In6.Cu")
		(net "M_D_CPU0_SB_DQ<23>")
	)
	(arc
		(start 335.332578 -229.597204)
		(mid 334.961855 -229.599296)
		(end 334.770984 -229.281482)
		(width 0.088646)
		(layer "In6.Cu")
		(net "M_D_CPU0_SB_DQ<23>")
	)
	(arc
		(start 343.702894 -230.484426)
		(mid 343.388824 -230.487795)
		(end 343.076276 -230.45674)
		(width 0.088646)
		(layer "In6.Cu")
		(net "M_D_CPU0_SB_DQ<23>")
	)
	(arc
		(start 335.887822 -229.591108)
		(mid 335.60939 -229.521294)
		(end 335.332578 -229.597204)
		(width 0.088646)
		(layer "In6.Cu")
		(net "M_D_CPU0_SB_DQ<23>")
	)
	(segment
		(start 345.01328 -232.250234)
		(end 345.01328 -231.714548)
		(width 0.20066)
		(layer "F.Cu")
		(net "M_D_CPU0_SB_DQ<22>")
	)
	(segment
		(start 262.50011 -206.23149)
		(end 261.762748 -206.23149)
		(width 0.20066)
		(layer "F.Cu")
		(net "M_D_CPU0_SB_DQ<22>")
	)
	(segment
		(start 262.765286 -206.24165)
		(end 262.51027 -206.24165)
		(width 0.101854)
		(layer "F.Cu")
		(net "M_D_CPU0_SB_DQ<22>")
	)
	(segment
		(start 264.825226 -206.24165)
		(end 262.765286 -206.24165)
		(width 0.1016)
		(layer "F.Cu")
		(net "M_D_CPU0_SB_DQ<22>")
	)
	(segment
		(start 261.327646 -206.666592)
		(end 260.180582 -206.666592)
		(width 0.20066)
		(layer "F.Cu")
		(net "M_D_CPU0_SB_DQ<22>")
	)
	(segment
		(start 268.829282 -206.666592)
		(end 267.724382 -206.666592)
		(width 0.20066)
		(layer "F.Cu")
		(net "M_D_CPU0_SB_DQ<22>")
	)
	(segment
		(start 345.013534 -232.250488)
		(end 345.01328 -232.250234)
		(width 0.20066)
		(layer "F.Cu")
		(net "M_D_CPU0_SB_DQ<22>")
	)
	(segment
		(start 265.601958 -206.711042)
		(end 265.601958 -206.385414)
		(width 0.20066)
		(layer "F.Cu")
		(net "M_D_CPU0_SB_DQ<22>")
	)
	(segment
		(start 261.762748 -206.23149)
		(end 261.327646 -206.666592)
		(width 0.20066)
		(layer "F.Cu")
		(net "M_D_CPU0_SB_DQ<22>")
	)
	(segment
		(start 266.409678 -206.666592)
		(end 266.197842 -206.878428)
		(width 0.20066)
		(layer "F.Cu")
		(net "M_D_CPU0_SB_DQ<22>")
	)
	(segment
		(start 265.458194 -206.24165)
		(end 264.825226 -206.24165)
		(width 0.20066)
		(layer "F.Cu")
		(net "M_D_CPU0_SB_DQ<22>")
	)
	(segment
		(start 262.51027 -206.24165)
		(end 262.50011 -206.23149)
		(width 0.101854)
		(layer "F.Cu")
		(net "M_D_CPU0_SB_DQ<22>")
	)
	(segment
		(start 265.601958 -206.385414)
		(end 265.458194 -206.24165)
		(width 0.20066)
		(layer "F.Cu")
		(net "M_D_CPU0_SB_DQ<22>")
	)
	(segment
		(start 267.724382 -206.666592)
		(end 266.409678 -206.666592)
		(width 0.20066)
		(layer "F.Cu")
		(net "M_D_CPU0_SB_DQ<22>")
	)
	(segment
		(start 266.197842 -206.878428)
		(end 265.769344 -206.878428)
		(width 0.20066)
		(layer "F.Cu")
		(net "M_D_CPU0_SB_DQ<22>")
	)
	(segment
		(start 265.769344 -206.878428)
		(end 265.601958 -206.711042)
		(width 0.20066)
		(layer "F.Cu")
		(net "M_D_CPU0_SB_DQ<22>")
	)
	(segment
		(start 338.247736 -230.41102)
		(end 338.237322 -230.404924)
		(width 0.088646)
		(layer "In6.Cu")
		(net "M_D_CPU0_SB_DQ<22>")
	)
	(segment
		(start 312.244994 -208.996026)
		(end 308.976014 -208.996026)
		(width 0.18288)
		(layer "In6.Cu")
		(net "M_D_CPU0_SB_DQ<22>")
	)
	(segment
		(start 276.862032 -206.402686)
		(end 275.588222 -206.402686)
		(width 0.18288)
		(layer "In6.Cu")
		(net "M_D_CPU0_SB_DQ<22>")
	)
	(segment
		(start 271.120362 -206.620872)
		(end 270.960342 -206.460852)
		(width 0.18288)
		(layer "In6.Cu")
		(net "M_D_CPU0_SB_DQ<22>")
	)
	(segment
		(start 274.531582 -206.402686)
		(end 273.943064 -206.402686)
		(width 0.18288)
		(layer "In6.Cu")
		(net "M_D_CPU0_SB_DQ<22>")
	)
	(segment
		(start 269.438882 -206.056992)
		(end 268.829282 -206.666592)
		(width 0.18288)
		(layer "In6.Cu")
		(net "M_D_CPU0_SB_DQ<22>")
	)
	(segment
		(start 332.161388 -229.648004)
		(end 331.949044 -229.43566)
		(width 0.088646)
		(layer "In6.Cu")
		(net "M_D_CPU0_SB_DQ<22>")
	)
	(segment
		(start 323.866764 -221.988634)
		(end 315.695838 -213.817708)
		(width 0.18288)
		(layer "In6.Cu")
		(net "M_D_CPU0_SB_DQ<22>")
	)
	(segment
		(start 307.279294 -207.903826)
		(end 306.999894 -208.183226)
		(width 0.18288)
		(layer "In6.Cu")
		(net "M_D_CPU0_SB_DQ<22>")
	)
	(segment
		(start 278.612092 -206.240888)
		(end 278.307038 -205.935834)
		(width 0.18288)
		(layer "In6.Cu")
		(net "M_D_CPU0_SB_DQ<22>")
	)
	(segment
		(start 334.301084 -230.095298)
		(end 334.301084 -230.086662)
		(width 0.088646)
		(layer "In6.Cu")
		(net "M_D_CPU0_SB_DQ<22>")
	)
	(segment
		(start 273.943064 -206.402686)
		(end 273.59737 -206.056992)
		(width 0.18288)
		(layer "In6.Cu")
		(net "M_D_CPU0_SB_DQ<22>")
	)
	(segment
		(start 314.232544 -211.110576)
		(end 314.02274 -211.110576)
		(width 0.18288)
		(layer "In6.Cu")
		(net "M_D_CPU0_SB_DQ<22>")
	)
	(segment
		(start 345.01328 -231.714548)
		(end 345.013026 -231.714294)
		(width 0.088646)
		(layer "In6.Cu")
		(net "M_D_CPU0_SB_DQ<22>")
	)
	(segment
		(start 270.960342 -206.217012)
		(end 270.800322 -206.056992)
		(width 0.18288)
		(layer "In6.Cu")
		(net "M_D_CPU0_SB_DQ<22>")
	)
	(segment
		(start 334.301084 -230.086662)
		(end 334.30083 -230.076756)
		(width 0.088646)
		(layer "In6.Cu")
		(net "M_D_CPU0_SB_DQ<22>")
	)
	(segment
		(start 304.668174 -208.183226)
		(end 303.977294 -208.183226)
		(width 0.18288)
		(layer "In6.Cu")
		(net "M_D_CPU0_SB_DQ<22>")
	)
	(segment
		(start 313.290712 -210.378548)
		(end 313.290712 -210.041744)
		(width 0.18288)
		(layer "In6.Cu")
		(net "M_D_CPU0_SB_DQ<22>")
	)
	(segment
		(start 303.977294 -208.183226)
		(end 303.037494 -207.243426)
		(width 0.18288)
		(layer "In6.Cu")
		(net "M_D_CPU0_SB_DQ<22>")
	)
	(segment
		(start 282.141168 -206.240888)
		(end 278.612092 -206.240888)
		(width 0.18288)
		(layer "In6.Cu")
		(net "M_D_CPU0_SB_DQ<22>")
	)
	(segment
		(start 275.405342 -206.219806)
		(end 275.405342 -206.101188)
		(width 0.18288)
		(layer "In6.Cu")
		(net "M_D_CPU0_SB_DQ<22>")
	)
	(segment
		(start 333.078836 -229.597458)
		(end 333.06512 -229.58933)
		(width 0.088646)
		(layer "In6.Cu")
		(net "M_D_CPU0_SB_DQ<22>")
	)
	(segment
		(start 271.653762 -206.217012)
		(end 271.653762 -206.460852)
		(width 0.18288)
		(layer "In6.Cu")
		(net "M_D_CPU0_SB_DQ<22>")
	)
	(segment
		(start 277.921212 -205.935834)
		(end 277.616158 -206.240888)
		(width 0.18288)
		(layer "In6.Cu")
		(net "M_D_CPU0_SB_DQ<22>")
	)
	(segment
		(start 337.307682 -230.41102)
		(end 337.29295 -230.402384)
		(width 0.088646)
		(layer "In6.Cu")
		(net "M_D_CPU0_SB_DQ<22>")
	)
	(segment
		(start 271.813782 -206.056992)
		(end 271.653762 -206.217012)
		(width 0.18288)
		(layer "In6.Cu")
		(net "M_D_CPU0_SB_DQ<22>")
	)
	(segment
		(start 275.222462 -205.918308)
		(end 274.897342 -205.918308)
		(width 0.18288)
		(layer "In6.Cu")
		(net "M_D_CPU0_SB_DQ<22>")
	)
	(segment
		(start 270.960342 -206.460852)
		(end 270.960342 -206.217012)
		(width 0.18288)
		(layer "In6.Cu")
		(net "M_D_CPU0_SB_DQ<22>")
	)
	(segment
		(start 305.541934 -207.691228)
		(end 305.359054 -207.508348)
		(width 0.18288)
		(layer "In6.Cu")
		(net "M_D_CPU0_SB_DQ<22>")
	)
	(segment
		(start 332.326234 -229.648004)
		(end 332.161388 -229.648004)
		(width 0.088646)
		(layer "In6.Cu")
		(net "M_D_CPU0_SB_DQ<22>")
	)
	(segment
		(start 278.307038 -205.935834)
		(end 277.921212 -205.935834)
		(width 0.18288)
		(layer "In6.Cu")
		(net "M_D_CPU0_SB_DQ<22>")
	)
	(segment
		(start 305.359054 -207.508348)
		(end 305.033934 -207.508348)
		(width 0.18288)
		(layer "In6.Cu")
		(net "M_D_CPU0_SB_DQ<22>")
	)
	(segment
		(start 277.616158 -206.240888)
		(end 277.02383 -206.240888)
		(width 0.18288)
		(layer "In6.Cu")
		(net "M_D_CPU0_SB_DQ<22>")
	)
	(segment
		(start 344.179398 -231.297226)
		(end 342.743282 -231.297226)
		(width 0.088646)
		(layer "In6.Cu")
		(net "M_D_CPU0_SB_DQ<22>")
	)
	(segment
		(start 285.747206 -205.39075)
		(end 285.40964 -205.728316)
		(width 0.18288)
		(layer "In6.Cu")
		(net "M_D_CPU0_SB_DQ<22>")
	)
	(segment
		(start 284.71876 -205.39075)
		(end 282.991306 -205.39075)
		(width 0.18288)
		(layer "In6.Cu")
		(net "M_D_CPU0_SB_DQ<22>")
	)
	(segment
		(start 338.530184 -230.909114)
		(end 338.530184 -230.890572)
		(width 0.088646)
		(layer "In6.Cu")
		(net "M_D_CPU0_SB_DQ<22>")
	)
	(segment
		(start 286.7914 -205.728316)
		(end 286.438086 -205.728316)
		(width 0.18288)
		(layer "In6.Cu")
		(net "M_D_CPU0_SB_DQ<22>")
	)
	(segment
		(start 335.802732 -230.41102)
		(end 335.79181 -230.41737)
		(width 0.088646)
		(layer "In6.Cu")
		(net "M_D_CPU0_SB_DQ<22>")
	)
	(segment
		(start 286.438086 -205.728316)
		(end 286.10052 -205.39075)
		(width 0.18288)
		(layer "In6.Cu")
		(net "M_D_CPU0_SB_DQ<22>")
	)
	(segment
		(start 335.428336 -230.411274)
		(end 335.411064 -230.401114)
		(width 0.088646)
		(layer "In6.Cu")
		(net "M_D_CPU0_SB_DQ<22>")
	)
	(segment
		(start 297.548046 -206.242412)
		(end 288.73196 -206.242412)
		(width 0.18288)
		(layer "In6.Cu")
		(net "M_D_CPU0_SB_DQ<22>")
	)
	(segment
		(start 270.800322 -206.056992)
		(end 269.438882 -206.056992)
		(width 0.18288)
		(layer "In6.Cu")
		(net "M_D_CPU0_SB_DQ<22>")
	)
	(segment
		(start 287.128966 -205.39075)
		(end 286.7914 -205.728316)
		(width 0.18288)
		(layer "In6.Cu")
		(net "M_D_CPU0_SB_DQ<22>")
	)
	(segment
		(start 314.816236 -211.694268)
		(end 314.232544 -211.110576)
		(width 0.18288)
		(layer "In6.Cu")
		(net "M_D_CPU0_SB_DQ<22>")
	)
	(segment
		(start 305.033934 -207.508348)
		(end 304.851054 -207.691228)
		(width 0.18288)
		(layer "In6.Cu")
		(net "M_D_CPU0_SB_DQ<22>")
	)
	(segment
		(start 275.588222 -206.402686)
		(end 275.405342 -206.219806)
		(width 0.18288)
		(layer "In6.Cu")
		(net "M_D_CPU0_SB_DQ<22>")
	)
	(segment
		(start 300.373034 -205.391766)
		(end 298.398692 -205.391766)
		(width 0.18288)
		(layer "In6.Cu")
		(net "M_D_CPU0_SB_DQ<22>")
	)
	(segment
		(start 313.290712 -210.041744)
		(end 312.244994 -208.996026)
		(width 0.18288)
		(layer "In6.Cu")
		(net "M_D_CPU0_SB_DQ<22>")
	)
	(segment
		(start 274.714462 -206.101188)
		(end 274.714462 -206.219806)
		(width 0.18288)
		(layer "In6.Cu")
		(net "M_D_CPU0_SB_DQ<22>")
	)
	(segment
		(start 339.102192 -231.21874)
		(end 339.091778 -231.224836)
		(width 0.088646)
		(layer "In6.Cu")
		(net "M_D_CPU0_SB_DQ<22>")
	)
	(segment
		(start 271.653762 -206.460852)
		(end 271.493742 -206.620872)
		(width 0.18288)
		(layer "In6.Cu")
		(net "M_D_CPU0_SB_DQ<22>")
	)
	(segment
		(start 308.976014 -208.996026)
		(end 307.883814 -207.903826)
		(width 0.18288)
		(layer "In6.Cu")
		(net "M_D_CPU0_SB_DQ<22>")
	)
	(segment
		(start 323.866764 -224.619312)
		(end 323.866764 -221.988634)
		(width 0.18288)
		(layer "In6.Cu")
		(net "M_D_CPU0_SB_DQ<22>")
	)
	(segment
		(start 274.714462 -206.219806)
		(end 274.531582 -206.402686)
		(width 0.18288)
		(layer "In6.Cu")
		(net "M_D_CPU0_SB_DQ<22>")
	)
	(segment
		(start 274.897342 -205.918308)
		(end 274.714462 -206.101188)
		(width 0.18288)
		(layer "In6.Cu")
		(net "M_D_CPU0_SB_DQ<22>")
	)
	(segment
		(start 285.40964 -205.728316)
		(end 285.056326 -205.728316)
		(width 0.18288)
		(layer "In6.Cu")
		(net "M_D_CPU0_SB_DQ<22>")
	)
	(segment
		(start 288.73196 -206.242412)
		(end 287.880298 -205.39075)
		(width 0.18288)
		(layer "In6.Cu")
		(net "M_D_CPU0_SB_DQ<22>")
	)
	(segment
		(start 330.41971 -227.351844)
		(end 326.599296 -227.351844)
		(width 0.18288)
		(layer "In6.Cu")
		(net "M_D_CPU0_SB_DQ<22>")
	)
	(segment
		(start 298.398692 -205.391766)
		(end 297.548046 -206.242412)
		(width 0.18288)
		(layer "In6.Cu")
		(net "M_D_CPU0_SB_DQ<22>")
	)
	(segment
		(start 287.880298 -205.39075)
		(end 287.128966 -205.39075)
		(width 0.18288)
		(layer "In6.Cu")
		(net "M_D_CPU0_SB_DQ<22>")
	)
	(segment
		(start 340.046564 -231.2162)
		(end 340.031832 -231.224836)
		(width 0.088646)
		(layer "In6.Cu")
		(net "M_D_CPU0_SB_DQ<22>")
	)
	(segment
		(start 330.681838 -227.351844)
		(end 330.41971 -227.351844)
		(width 0.088646)
		(layer "In6.Cu")
		(net "M_D_CPU0_SB_DQ<22>")
	)
	(segment
		(start 304.851054 -207.691228)
		(end 304.851054 -208.000346)
		(width 0.18288)
		(layer "In6.Cu")
		(net "M_D_CPU0_SB_DQ<22>")
	)
	(segment
		(start 273.59737 -206.056992)
		(end 271.813782 -206.056992)
		(width 0.18288)
		(layer "In6.Cu")
		(net "M_D_CPU0_SB_DQ<22>")
	)
	(segment
		(start 306.999894 -208.183226)
		(end 305.724814 -208.183226)
		(width 0.18288)
		(layer "In6.Cu")
		(net "M_D_CPU0_SB_DQ<22>")
	)
	(segment
		(start 340.986364 -231.2162)
		(end 340.971632 -231.224836)
		(width 0.088646)
		(layer "In6.Cu")
		(net "M_D_CPU0_SB_DQ<22>")
	)
	(segment
		(start 305.724814 -208.183226)
		(end 305.541934 -208.000346)
		(width 0.18288)
		(layer "In6.Cu")
		(net "M_D_CPU0_SB_DQ<22>")
	)
	(segment
		(start 304.851054 -208.000346)
		(end 304.668174 -208.183226)
		(width 0.18288)
		(layer "In6.Cu")
		(net "M_D_CPU0_SB_DQ<22>")
	)
	(segment
		(start 282.991306 -205.39075)
		(end 282.141168 -206.240888)
		(width 0.18288)
		(layer "In6.Cu")
		(net "M_D_CPU0_SB_DQ<22>")
	)
	(segment
		(start 303.037494 -207.243426)
		(end 302.224694 -207.243426)
		(width 0.18288)
		(layer "In6.Cu")
		(net "M_D_CPU0_SB_DQ<22>")
	)
	(segment
		(start 275.405342 -206.101188)
		(end 275.222462 -205.918308)
		(width 0.18288)
		(layer "In6.Cu")
		(net "M_D_CPU0_SB_DQ<22>")
	)
	(segment
		(start 302.224694 -207.243426)
		(end 300.373034 -205.391766)
		(width 0.18288)
		(layer "In6.Cu")
		(net "M_D_CPU0_SB_DQ<22>")
	)
	(segment
		(start 286.10052 -205.39075)
		(end 285.747206 -205.39075)
		(width 0.18288)
		(layer "In6.Cu")
		(net "M_D_CPU0_SB_DQ<22>")
	)
	(segment
		(start 285.056326 -205.728316)
		(end 284.71876 -205.39075)
		(width 0.18288)
		(layer "In6.Cu")
		(net "M_D_CPU0_SB_DQ<22>")
	)
	(segment
		(start 315.695838 -213.817708)
		(end 314.816236 -211.694268)
		(width 0.18288)
		(layer "In6.Cu")
		(net "M_D_CPU0_SB_DQ<22>")
	)
	(segment
		(start 331.949044 -229.43566)
		(end 331.949044 -228.61905)
		(width 0.088646)
		(layer "In6.Cu")
		(net "M_D_CPU0_SB_DQ<22>")
	)
	(segment
		(start 326.599296 -227.351844)
		(end 323.866764 -224.619312)
		(width 0.18288)
		(layer "In6.Cu")
		(net "M_D_CPU0_SB_DQ<22>")
	)
	(segment
		(start 336.367882 -230.41102)
		(end 336.357468 -230.404924)
		(width 0.088646)
		(layer "In6.Cu")
		(net "M_D_CPU0_SB_DQ<22>")
	)
	(segment
		(start 314.02274 -211.110576)
		(end 313.290712 -210.378548)
		(width 0.18288)
		(layer "In6.Cu")
		(net "M_D_CPU0_SB_DQ<22>")
	)
	(segment
		(start 331.949044 -228.61905)
		(end 330.681838 -227.351844)
		(width 0.088646)
		(layer "In6.Cu")
		(net "M_D_CPU0_SB_DQ<22>")
	)
	(segment
		(start 271.493742 -206.620872)
		(end 271.120362 -206.620872)
		(width 0.18288)
		(layer "In6.Cu")
		(net "M_D_CPU0_SB_DQ<22>")
	)
	(segment
		(start 305.541934 -208.000346)
		(end 305.541934 -207.691228)
		(width 0.18288)
		(layer "In6.Cu")
		(net "M_D_CPU0_SB_DQ<22>")
	)
	(segment
		(start 277.02383 -206.240888)
		(end 276.862032 -206.402686)
		(width 0.18288)
		(layer "In6.Cu")
		(net "M_D_CPU0_SB_DQ<22>")
	)
	(segment
		(start 307.883814 -207.903826)
		(end 307.279294 -207.903826)
		(width 0.18288)
		(layer "In6.Cu")
		(net "M_D_CPU0_SB_DQ<22>")
	)
	(arc
		(start 339.657436 -231.224836)
		(mid 339.380623 -231.149)
		(end 339.102192 -231.21874)
		(width 0.088646)
		(layer "In6.Cu")
		(net "M_D_CPU0_SB_DQ<22>")
	)
	(arc
		(start 334.862678 -230.41102)
		(mid 334.67548 -230.461163)
		(end 334.488282 -230.41102)
		(width 0.088646)
		(layer "In6.Cu")
		(net "M_D_CPU0_SB_DQ<22>")
	)
	(arc
		(start 333.453232 -229.597458)
		(mid 333.266034 -229.647601)
		(end 333.078836 -229.597458)
		(width 0.088646)
		(layer "In6.Cu")
		(net "M_D_CPU0_SB_DQ<22>")
	)
	(arc
		(start 338.530184 -230.890572)
		(mid 338.452073 -230.613623)
		(end 338.247736 -230.41102)
		(width 0.088646)
		(layer "In6.Cu")
		(net "M_D_CPU0_SB_DQ<22>")
	)
	(arc
		(start 341.537036 -231.224836)
		(mid 341.262807 -231.148911)
		(end 340.986364 -231.2162)
		(width 0.088646)
		(layer "In6.Cu")
		(net "M_D_CPU0_SB_DQ<22>")
	)
	(arc
		(start 342.743282 -231.297226)
		(mid 342.60536 -231.278327)
		(end 342.476836 -231.224836)
		(width 0.088646)
		(layer "In6.Cu")
		(net "M_D_CPU0_SB_DQ<22>")
	)
	(arc
		(start 334.30083 -230.076756)
		(mid 334.222807 -229.799957)
		(end 334.018636 -229.597458)
		(width 0.088646)
		(layer "In6.Cu")
		(net "M_D_CPU0_SB_DQ<22>")
	)
	(arc
		(start 342.476836 -231.224836)
		(mid 342.194134 -231.149094)
		(end 341.911432 -231.224836)
		(width 0.088646)
		(layer "In6.Cu")
		(net "M_D_CPU0_SB_DQ<22>")
	)
	(arc
		(start 335.79181 -230.41737)
		(mid 335.60928 -230.461394)
		(end 335.428336 -230.411274)
		(width 0.088646)
		(layer "In6.Cu")
		(net "M_D_CPU0_SB_DQ<22>")
	)
	(arc
		(start 336.357468 -230.404924)
		(mid 336.07929 -230.335201)
		(end 335.802732 -230.41102)
		(width 0.088646)
		(layer "In6.Cu")
		(net "M_D_CPU0_SB_DQ<22>")
	)
	(arc
		(start 334.488282 -230.41102)
		(mid 334.353349 -230.277666)
		(end 334.301084 -230.095298)
		(width 0.088646)
		(layer "In6.Cu")
		(net "M_D_CPU0_SB_DQ<22>")
	)
	(arc
		(start 338.237322 -230.404924)
		(mid 337.95889 -230.335078)
		(end 337.682078 -230.41102)
		(width 0.088646)
		(layer "In6.Cu")
		(net "M_D_CPU0_SB_DQ<22>")
	)
	(arc
		(start 336.742278 -230.41102)
		(mid 336.55508 -230.461163)
		(end 336.367882 -230.41102)
		(width 0.088646)
		(layer "In6.Cu")
		(net "M_D_CPU0_SB_DQ<22>")
	)
	(arc
		(start 332.513432 -229.597204)
		(mid 332.423176 -229.634926)
		(end 332.326234 -229.648004)
		(width 0.088646)
		(layer "In6.Cu")
		(net "M_D_CPU0_SB_DQ<22>")
	)
	(arc
		(start 337.682078 -230.41102)
		(mid 337.49488 -230.461163)
		(end 337.307682 -230.41102)
		(width 0.088646)
		(layer "In6.Cu")
		(net "M_D_CPU0_SB_DQ<22>")
	)
	(arc
		(start 344.268044 -231.306624)
		(mid 344.223975 -231.299533)
		(end 344.179398 -231.297226)
		(width 0.088646)
		(layer "In6.Cu")
		(net "M_D_CPU0_SB_DQ<22>")
	)
	(arc
		(start 335.411064 -230.401114)
		(mid 335.135601 -230.335196)
		(end 334.862678 -230.41102)
		(width 0.088646)
		(layer "In6.Cu")
		(net "M_D_CPU0_SB_DQ<22>")
	)
	(arc
		(start 340.971632 -231.224836)
		(mid 340.784434 -231.274979)
		(end 340.597236 -231.224836)
		(width 0.088646)
		(layer "In6.Cu")
		(net "M_D_CPU0_SB_DQ<22>")
	)
	(arc
		(start 339.091778 -231.224836)
		(mid 338.90458 -231.274979)
		(end 338.717382 -231.224836)
		(width 0.088646)
		(layer "In6.Cu")
		(net "M_D_CPU0_SB_DQ<22>")
	)
	(arc
		(start 340.597236 -231.224836)
		(mid 340.323007 -231.148911)
		(end 340.046564 -231.2162)
		(width 0.088646)
		(layer "In6.Cu")
		(net "M_D_CPU0_SB_DQ<22>")
	)
	(arc
		(start 340.031832 -231.224836)
		(mid 339.844634 -231.274979)
		(end 339.657436 -231.224836)
		(width 0.088646)
		(layer "In6.Cu")
		(net "M_D_CPU0_SB_DQ<22>")
	)
	(arc
		(start 337.29295 -230.402384)
		(mid 337.016475 -230.335064)
		(end 336.742278 -230.41102)
		(width 0.088646)
		(layer "In6.Cu")
		(net "M_D_CPU0_SB_DQ<22>")
	)
	(arc
		(start 341.911432 -231.224836)
		(mid 341.724234 -231.274979)
		(end 341.537036 -231.224836)
		(width 0.088646)
		(layer "In6.Cu")
		(net "M_D_CPU0_SB_DQ<22>")
	)
	(arc
		(start 334.018636 -229.597458)
		(mid 333.735934 -229.521682)
		(end 333.453232 -229.597458)
		(width 0.088646)
		(layer "In6.Cu")
		(net "M_D_CPU0_SB_DQ<22>")
	)
	(arc
		(start 338.717382 -231.224836)
		(mid 338.582449 -231.091482)
		(end 338.530184 -230.909114)
		(width 0.088646)
		(layer "In6.Cu")
		(net "M_D_CPU0_SB_DQ<22>")
	)
	(arc
		(start 345.013026 -231.714294)
		(mid 344.669771 -231.457036)
		(end 344.268044 -231.306624)
		(width 0.088646)
		(layer "In6.Cu")
		(net "M_D_CPU0_SB_DQ<22>")
	)
	(arc
		(start 333.06512 -229.58933)
		(mid 332.78826 -229.521458)
		(end 332.513432 -229.597204)
		(width 0.088646)
		(layer "In6.Cu")
		(net "M_D_CPU0_SB_DQ<22>")
	)
	(segment
		(start 258.28498 -205.873604)
		(end 258.130548 -206.028036)
		(width 0.20066)
		(layer "F.Cu")
		(net "M_D_CPU0_SB_DQ<21>")
	)
	(segment
		(start 259.065268 -205.391766)
		(end 259.056378 -205.382876)
		(width 0.1016)
		(layer "F.Cu")
		(net "M_D_CPU0_SB_DQ<21>")
	)
	(segment
		(start 257.626104 -206.028036)
		(end 257.414776 -205.816708)
		(width 0.20066)
		(layer "F.Cu")
		(net "M_D_CPU0_SB_DQ<21>")
	)
	(segment
		(start 257.414776 -205.816708)
		(end 256.080514 -205.816708)
		(width 0.20066)
		(layer "F.Cu")
		(net "M_D_CPU0_SB_DQ<21>")
	)
	(segment
		(start 343.603834 -231.436164)
		(end 343.603834 -230.900478)
		(width 0.20066)
		(layer "F.Cu")
		(net "M_D_CPU0_SB_DQ<21>")
	)
	(segment
		(start 261.560056 -205.391766)
		(end 261.381494 -205.391766)
		(width 0.20066)
		(layer "F.Cu")
		(net "M_D_CPU0_SB_DQ<21>")
	)
	(segment
		(start 264.729214 -205.816708)
		(end 263.624314 -205.816708)
		(width 0.20066)
		(layer "F.Cu")
		(net "M_D_CPU0_SB_DQ<21>")
	)
	(segment
		(start 343.60358 -231.436418)
		(end 343.603834 -231.436164)
		(width 0.20066)
		(layer "F.Cu")
		(net "M_D_CPU0_SB_DQ<21>")
	)
	(segment
		(start 261.050786 -205.391766)
		(end 259.065268 -205.391766)
		(width 0.1016)
		(layer "F.Cu")
		(net "M_D_CPU0_SB_DQ<21>")
	)
	(segment
		(start 258.130548 -206.028036)
		(end 257.626104 -206.028036)
		(width 0.20066)
		(layer "F.Cu")
		(net "M_D_CPU0_SB_DQ<21>")
	)
	(segment
		(start 258.28498 -205.545436)
		(end 258.28498 -205.873604)
		(width 0.20066)
		(layer "F.Cu")
		(net "M_D_CPU0_SB_DQ<21>")
	)
	(segment
		(start 259.056378 -205.382876)
		(end 258.44754 -205.382876)
		(width 0.20066)
		(layer "F.Cu")
		(net "M_D_CPU0_SB_DQ<21>")
	)
	(segment
		(start 261.984998 -205.816708)
		(end 261.560056 -205.391766)
		(width 0.20066)
		(layer "F.Cu")
		(net "M_D_CPU0_SB_DQ<21>")
	)
	(segment
		(start 258.44754 -205.382876)
		(end 258.28498 -205.545436)
		(width 0.20066)
		(layer "F.Cu")
		(net "M_D_CPU0_SB_DQ<21>")
	)
	(segment
		(start 263.624314 -205.816708)
		(end 261.984998 -205.816708)
		(width 0.20066)
		(layer "F.Cu")
		(net "M_D_CPU0_SB_DQ<21>")
	)
	(segment
		(start 261.381494 -205.391766)
		(end 261.050786 -205.391766)
		(width 0.101854)
		(layer "F.Cu")
		(net "M_D_CPU0_SB_DQ<21>")
	)
	(segment
		(start 302.935894 -206.125826)
		(end 302.132492 -206.125826)
		(width 0.18288)
		(layer "In6.Cu")
		(net "M_D_CPU0_SB_DQ<21>")
	)
	(segment
		(start 294.556688 -205.392274)
		(end 294.20439 -205.744572)
		(width 0.18288)
		(layer "In6.Cu")
		(net "M_D_CPU0_SB_DQ<21>")
	)
	(segment
		(start 324.40499 -221.759526)
		(end 316.207394 -213.56193)
		(width 0.18288)
		(layer "In6.Cu")
		(net "M_D_CPU0_SB_DQ<21>")
	)
	(segment
		(start 338.247736 -229.762304)
		(end 338.237322 -229.7684)
		(width 0.088646)
		(layer "In6.Cu")
		(net "M_D_CPU0_SB_DQ<21>")
	)
	(segment
		(start 266.706858 -205.038706)
		(end 266.706858 -204.765148)
		(width 0.18288)
		(layer "In6.Cu")
		(net "M_D_CPU0_SB_DQ<21>")
	)
	(segment
		(start 333.453232 -228.948742)
		(end 333.453486 -228.948488)
		(width 0.088646)
		(layer "In6.Cu")
		(net "M_D_CPU0_SB_DQ<21>")
	)
	(segment
		(start 266.015978 -204.765148)
		(end 266.015978 -205.038706)
		(width 0.18288)
		(layer "In6.Cu")
		(net "M_D_CPU0_SB_DQ<21>")
	)
	(segment
		(start 306.936394 -206.913226)
		(end 303.723294 -206.913226)
		(width 0.18288)
		(layer "In6.Cu")
		(net "M_D_CPU0_SB_DQ<21>")
	)
	(segment
		(start 265.324336 -205.221586)
		(end 264.729214 -205.816708)
		(width 0.18288)
		(layer "In6.Cu")
		(net "M_D_CPU0_SB_DQ<21>")
	)
	(segment
		(start 310.993028 -207.878426)
		(end 308.779926 -207.878426)
		(width 0.18288)
		(layer "In6.Cu")
		(net "M_D_CPU0_SB_DQ<21>")
	)
	(segment
		(start 266.198858 -204.582268)
		(end 266.015978 -204.765148)
		(width 0.18288)
		(layer "In6.Cu")
		(net "M_D_CPU0_SB_DQ<21>")
	)
	(segment
		(start 340.046564 -230.584756)
		(end 340.031832 -230.57612)
		(width 0.088646)
		(layer "In6.Cu")
		(net "M_D_CPU0_SB_DQ<21>")
	)
	(segment
		(start 332.230984 -228.45903)
		(end 332.230984 -228.36251)
		(width 0.088646)
		(layer "In6.Cu")
		(net "M_D_CPU0_SB_DQ<21>")
	)
	(segment
		(start 337.307682 -229.762304)
		(end 337.29295 -229.77094)
		(width 0.088646)
		(layer "In6.Cu")
		(net "M_D_CPU0_SB_DQ<21>")
	)
	(segment
		(start 332.230984 -228.36251)
		(end 330.722478 -226.854004)
		(width 0.088646)
		(layer "In6.Cu")
		(net "M_D_CPU0_SB_DQ<21>")
	)
	(segment
		(start 307.23332 -207.210152)
		(end 306.936394 -206.913226)
		(width 0.18288)
		(layer "In6.Cu")
		(net "M_D_CPU0_SB_DQ<21>")
	)
	(segment
		(start 315.300868 -211.373212)
		(end 314.479686 -210.55203)
		(width 0.18288)
		(layer "In6.Cu")
		(net "M_D_CPU0_SB_DQ<21>")
	)
	(segment
		(start 291.71138 -205.392274)
		(end 289.047174 -205.392274)
		(width 0.18288)
		(layer "In6.Cu")
		(net "M_D_CPU0_SB_DQ<21>")
	)
	(segment
		(start 288.197036 -204.542136)
		(end 283.558996 -204.542136)
		(width 0.18288)
		(layer "In6.Cu")
		(net "M_D_CPU0_SB_DQ<21>")
	)
	(segment
		(start 308.111652 -207.210152)
		(end 307.23332 -207.210152)
		(width 0.18288)
		(layer "In6.Cu")
		(net "M_D_CPU0_SB_DQ<21>")
	)
	(segment
		(start 338.80933 -230.096568)
		(end 338.80933 -230.078026)
		(width 0.088646)
		(layer "In6.Cu")
		(net "M_D_CPU0_SB_DQ<21>")
	)
	(segment
		(start 300.548294 -204.541628)
		(end 298.341034 -204.541628)
		(width 0.18288)
		(layer "In6.Cu")
		(net "M_D_CPU0_SB_DQ<21>")
	)
	(segment
		(start 334.87995 -229.772464)
		(end 334.862678 -229.762304)
		(width 0.088646)
		(layer "In6.Cu")
		(net "M_D_CPU0_SB_DQ<21>")
	)
	(segment
		(start 313.818016 -209.782918)
		(end 312.21426 -208.179162)
		(width 0.18288)
		(layer "In6.Cu")
		(net "M_D_CPU0_SB_DQ<21>")
	)
	(segment
		(start 265.833098 -205.221586)
		(end 265.324336 -205.221586)
		(width 0.18288)
		(layer "In6.Cu")
		(net "M_D_CPU0_SB_DQ<21>")
	)
	(segment
		(start 324.40499 -224.403412)
		(end 324.40499 -221.759526)
		(width 0.18288)
		(layer "In6.Cu")
		(net "M_D_CPU0_SB_DQ<21>")
	)
	(segment
		(start 314.176664 -210.55203)
		(end 313.818016 -210.193382)
		(width 0.18288)
		(layer "In6.Cu")
		(net "M_D_CPU0_SB_DQ<21>")
	)
	(segment
		(start 282.675076 -204.741272)
		(end 282.024074 -205.392274)
		(width 0.18288)
		(layer "In6.Cu")
		(net "M_D_CPU0_SB_DQ<21>")
	)
	(segment
		(start 266.523978 -204.582268)
		(end 266.198858 -204.582268)
		(width 0.18288)
		(layer "In6.Cu")
		(net "M_D_CPU0_SB_DQ<21>")
	)
	(segment
		(start 314.479686 -210.55203)
		(end 314.176664 -210.55203)
		(width 0.18288)
		(layer "In6.Cu")
		(net "M_D_CPU0_SB_DQ<21>")
	)
	(segment
		(start 330.41971 -226.854004)
		(end 326.855582 -226.854004)
		(width 0.18288)
		(layer "In6.Cu")
		(net "M_D_CPU0_SB_DQ<21>")
	)
	(segment
		(start 334.580484 -229.283006)
		(end 334.58023 -229.2731)
		(width 0.088646)
		(layer "In6.Cu")
		(net "M_D_CPU0_SB_DQ<21>")
	)
	(segment
		(start 313.818016 -210.193382)
		(end 313.818016 -209.782918)
		(width 0.18288)
		(layer "In6.Cu")
		(net "M_D_CPU0_SB_DQ<21>")
	)
	(segment
		(start 336.367882 -229.762304)
		(end 336.35061 -229.77221)
		(width 0.088646)
		(layer "In6.Cu")
		(net "M_D_CPU0_SB_DQ<21>")
	)
	(segment
		(start 294.20439 -205.744572)
		(end 292.063678 -205.744572)
		(width 0.18288)
		(layer "In6.Cu")
		(net "M_D_CPU0_SB_DQ<21>")
	)
	(segment
		(start 311.293764 -208.179162)
		(end 310.993028 -207.878426)
		(width 0.18288)
		(layer "In6.Cu")
		(net "M_D_CPU0_SB_DQ<21>")
	)
	(segment
		(start 334.58023 -229.2731)
		(end 334.58023 -229.264464)
		(width 0.088646)
		(layer "In6.Cu")
		(net "M_D_CPU0_SB_DQ<21>")
	)
	(segment
		(start 297.490388 -205.392274)
		(end 294.556688 -205.392274)
		(width 0.18288)
		(layer "In6.Cu")
		(net "M_D_CPU0_SB_DQ<21>")
	)
	(segment
		(start 326.855582 -226.854004)
		(end 324.40499 -224.403412)
		(width 0.18288)
		(layer "In6.Cu")
		(net "M_D_CPU0_SB_DQ<21>")
	)
	(segment
		(start 267.645388 -205.392274)
		(end 267.4747 -205.221586)
		(width 0.18288)
		(layer "In6.Cu")
		(net "M_D_CPU0_SB_DQ<21>")
	)
	(segment
		(start 282.024074 -205.392274)
		(end 267.645388 -205.392274)
		(width 0.18288)
		(layer "In6.Cu")
		(net "M_D_CPU0_SB_DQ<21>")
	)
	(segment
		(start 303.723294 -206.913226)
		(end 302.935894 -206.125826)
		(width 0.18288)
		(layer "In6.Cu")
		(net "M_D_CPU0_SB_DQ<21>")
	)
	(segment
		(start 266.889738 -205.221586)
		(end 266.706858 -205.038706)
		(width 0.18288)
		(layer "In6.Cu")
		(net "M_D_CPU0_SB_DQ<21>")
	)
	(segment
		(start 302.132492 -206.125826)
		(end 300.548294 -204.541628)
		(width 0.18288)
		(layer "In6.Cu")
		(net "M_D_CPU0_SB_DQ<21>")
	)
	(segment
		(start 312.21426 -208.179162)
		(end 311.293764 -208.179162)
		(width 0.18288)
		(layer "In6.Cu")
		(net "M_D_CPU0_SB_DQ<21>")
	)
	(segment
		(start 308.779926 -207.878426)
		(end 308.111652 -207.210152)
		(width 0.18288)
		(layer "In6.Cu")
		(net "M_D_CPU0_SB_DQ<21>")
	)
	(segment
		(start 330.722478 -226.854004)
		(end 330.41971 -226.854004)
		(width 0.088646)
		(layer "In6.Cu")
		(net "M_D_CPU0_SB_DQ<21>")
	)
	(segment
		(start 298.341034 -204.541628)
		(end 297.490388 -205.392274)
		(width 0.18288)
		(layer "In6.Cu")
		(net "M_D_CPU0_SB_DQ<21>")
	)
	(segment
		(start 266.706858 -204.765148)
		(end 266.523978 -204.582268)
		(width 0.18288)
		(layer "In6.Cu")
		(net "M_D_CPU0_SB_DQ<21>")
	)
	(segment
		(start 266.015978 -205.038706)
		(end 265.833098 -205.221586)
		(width 0.18288)
		(layer "In6.Cu")
		(net "M_D_CPU0_SB_DQ<21>")
	)
	(segment
		(start 283.35986 -204.741272)
		(end 282.675076 -204.741272)
		(width 0.18288)
		(layer "In6.Cu")
		(net "M_D_CPU0_SB_DQ<21>")
	)
	(segment
		(start 292.063678 -205.744572)
		(end 291.71138 -205.392274)
		(width 0.18288)
		(layer "In6.Cu")
		(net "M_D_CPU0_SB_DQ<21>")
	)
	(segment
		(start 289.047174 -205.392274)
		(end 288.197036 -204.542136)
		(width 0.18288)
		(layer "In6.Cu")
		(net "M_D_CPU0_SB_DQ<21>")
	)
	(segment
		(start 340.986364 -230.584756)
		(end 340.971632 -230.57612)
		(width 0.088646)
		(layer "In6.Cu")
		(net "M_D_CPU0_SB_DQ<21>")
	)
	(segment
		(start 267.4747 -205.221586)
		(end 266.889738 -205.221586)
		(width 0.18288)
		(layer "In6.Cu")
		(net "M_D_CPU0_SB_DQ<21>")
	)
	(segment
		(start 333.07909 -228.948488)
		(end 333.068676 -228.954584)
		(width 0.088646)
		(layer "In6.Cu")
		(net "M_D_CPU0_SB_DQ<21>")
	)
	(segment
		(start 341.926164 -230.584756)
		(end 341.911432 -230.57612)
		(width 0.088646)
		(layer "In6.Cu")
		(net "M_D_CPU0_SB_DQ<21>")
	)
	(segment
		(start 316.207394 -213.56193)
		(end 315.300868 -211.373212)
		(width 0.18288)
		(layer "In6.Cu")
		(net "M_D_CPU0_SB_DQ<21>")
	)
	(segment
		(start 342.865964 -230.584756)
		(end 342.851232 -230.57612)
		(width 0.088646)
		(layer "In6.Cu")
		(net "M_D_CPU0_SB_DQ<21>")
	)
	(segment
		(start 283.558996 -204.542136)
		(end 283.35986 -204.741272)
		(width 0.18288)
		(layer "In6.Cu")
		(net "M_D_CPU0_SB_DQ<21>")
	)
	(arc
		(start 340.597236 -230.57612)
		(mid 340.323037 -230.651955)
		(end 340.046564 -230.584756)
		(width 0.088646)
		(layer "In6.Cu")
		(net "M_D_CPU0_SB_DQ<21>")
	)
	(arc
		(start 340.971632 -230.57612)
		(mid 340.784434 -230.525977)
		(end 340.597236 -230.57612)
		(width 0.088646)
		(layer "In6.Cu")
		(net "M_D_CPU0_SB_DQ<21>")
	)
	(arc
		(start 339.657436 -230.57612)
		(mid 339.096239 -230.578816)
		(end 338.80933 -230.096568)
		(width 0.088646)
		(layer "In6.Cu")
		(net "M_D_CPU0_SB_DQ<21>")
	)
	(arc
		(start 334.862678 -229.762304)
		(mid 334.658589 -229.559757)
		(end 334.580484 -229.283006)
		(width 0.088646)
		(layer "In6.Cu")
		(net "M_D_CPU0_SB_DQ<21>")
	)
	(arc
		(start 335.428336 -229.762558)
		(mid 335.155414 -229.838461)
		(end 334.87995 -229.772464)
		(width 0.088646)
		(layer "In6.Cu")
		(net "M_D_CPU0_SB_DQ<21>")
	)
	(arc
		(start 336.35061 -229.77221)
		(mid 336.07543 -229.838162)
		(end 335.802732 -229.762558)
		(width 0.088646)
		(layer "In6.Cu")
		(net "M_D_CPU0_SB_DQ<21>")
	)
	(arc
		(start 341.911432 -230.57612)
		(mid 341.724234 -230.525977)
		(end 341.537036 -230.57612)
		(width 0.088646)
		(layer "In6.Cu")
		(net "M_D_CPU0_SB_DQ<21>")
	)
	(arc
		(start 334.018636 -228.948742)
		(mid 333.735934 -229.024518)
		(end 333.453232 -228.948742)
		(width 0.088646)
		(layer "In6.Cu")
		(net "M_D_CPU0_SB_DQ<21>")
	)
	(arc
		(start 337.682078 -229.762304)
		(mid 337.49488 -229.712161)
		(end 337.307682 -229.762304)
		(width 0.088646)
		(layer "In6.Cu")
		(net "M_D_CPU0_SB_DQ<21>")
	)
	(arc
		(start 343.603834 -230.900478)
		(mid 343.28019 -230.749615)
		(end 342.947244 -230.62057)
		(width 0.088646)
		(layer "In6.Cu")
		(net "M_D_CPU0_SB_DQ<21>")
	)
	(arc
		(start 333.068676 -228.954584)
		(mid 332.508504 -228.94569)
		(end 332.230984 -228.45903)
		(width 0.088646)
		(layer "In6.Cu")
		(net "M_D_CPU0_SB_DQ<21>")
	)
	(arc
		(start 338.80933 -230.078026)
		(mid 338.618456 -229.760217)
		(end 338.247736 -229.762304)
		(width 0.088646)
		(layer "In6.Cu")
		(net "M_D_CPU0_SB_DQ<21>")
	)
	(arc
		(start 342.947244 -230.62057)
		(mid 342.905902 -230.604257)
		(end 342.865964 -230.584756)
		(width 0.088646)
		(layer "In6.Cu")
		(net "M_D_CPU0_SB_DQ<21>")
	)
	(arc
		(start 340.031832 -230.57612)
		(mid 339.844634 -230.525977)
		(end 339.657436 -230.57612)
		(width 0.088646)
		(layer "In6.Cu")
		(net "M_D_CPU0_SB_DQ<21>")
	)
	(arc
		(start 337.29295 -229.77094)
		(mid 337.016475 -229.83826)
		(end 336.742278 -229.762304)
		(width 0.088646)
		(layer "In6.Cu")
		(net "M_D_CPU0_SB_DQ<21>")
	)
	(arc
		(start 334.58023 -229.264464)
		(mid 334.389356 -228.946655)
		(end 334.018636 -228.948742)
		(width 0.088646)
		(layer "In6.Cu")
		(net "M_D_CPU0_SB_DQ<21>")
	)
	(arc
		(start 342.476836 -230.57612)
		(mid 342.202637 -230.651955)
		(end 341.926164 -230.584756)
		(width 0.088646)
		(layer "In6.Cu")
		(net "M_D_CPU0_SB_DQ<21>")
	)
	(arc
		(start 333.453486 -228.948488)
		(mid 333.266288 -228.898345)
		(end 333.07909 -228.948488)
		(width 0.088646)
		(layer "In6.Cu")
		(net "M_D_CPU0_SB_DQ<21>")
	)
	(arc
		(start 338.237322 -229.7684)
		(mid 337.95889 -229.838246)
		(end 337.682078 -229.762304)
		(width 0.088646)
		(layer "In6.Cu")
		(net "M_D_CPU0_SB_DQ<21>")
	)
	(arc
		(start 341.537036 -230.57612)
		(mid 341.262837 -230.651955)
		(end 340.986364 -230.584756)
		(width 0.088646)
		(layer "In6.Cu")
		(net "M_D_CPU0_SB_DQ<21>")
	)
	(arc
		(start 335.802732 -229.762558)
		(mid 335.615534 -229.712415)
		(end 335.428336 -229.762558)
		(width 0.088646)
		(layer "In6.Cu")
		(net "M_D_CPU0_SB_DQ<21>")
	)
	(arc
		(start 342.851232 -230.57612)
		(mid 342.664034 -230.525977)
		(end 342.476836 -230.57612)
		(width 0.088646)
		(layer "In6.Cu")
		(net "M_D_CPU0_SB_DQ<21>")
	)
	(arc
		(start 336.742278 -229.762304)
		(mid 336.55508 -229.712161)
		(end 336.367882 -229.762304)
		(width 0.088646)
		(layer "In6.Cu")
		(net "M_D_CPU0_SB_DQ<21>")
	)
	(segment
		(start 258.28498 -207.29321)
		(end 258.28498 -207.58277)
		(width 0.20066)
		(layer "F.Cu")
		(net "M_D_CPU0_SB_DQ<20>")
	)
	(segment
		(start 258.28498 -207.58277)
		(end 258.11226 -207.75549)
		(width 0.20066)
		(layer "F.Cu")
		(net "M_D_CPU0_SB_DQ<20>")
	)
	(segment
		(start 261.830312 -207.091788)
		(end 261.381494 -207.091788)
		(width 0.20066)
		(layer "F.Cu")
		(net "M_D_CPU0_SB_DQ<20>")
	)
	(segment
		(start 257.414776 -207.51673)
		(end 256.080514 -207.51673)
		(width 0.20066)
		(layer "F.Cu")
		(net "M_D_CPU0_SB_DQ<20>")
	)
	(segment
		(start 258.11226 -207.75549)
		(end 257.653536 -207.75549)
		(width 0.20066)
		(layer "F.Cu")
		(net "M_D_CPU0_SB_DQ<20>")
	)
	(segment
		(start 259.064506 -207.091788)
		(end 259.056378 -207.08366)
		(width 0.101854)
		(layer "F.Cu")
		(net "M_D_CPU0_SB_DQ<20>")
	)
	(segment
		(start 258.49453 -207.08366)
		(end 258.28498 -207.29321)
		(width 0.20066)
		(layer "F.Cu")
		(net "M_D_CPU0_SB_DQ<20>")
	)
	(segment
		(start 261.381494 -207.091788)
		(end 259.31241 -207.091788)
		(width 0.1016)
		(layer "F.Cu")
		(net "M_D_CPU0_SB_DQ<20>")
	)
	(segment
		(start 343.133934 -232.250488)
		(end 343.13368 -232.250234)
		(width 0.20066)
		(layer "F.Cu")
		(net "M_D_CPU0_SB_DQ<20>")
	)
	(segment
		(start 257.653536 -207.75549)
		(end 257.414776 -207.51673)
		(width 0.20066)
		(layer "F.Cu")
		(net "M_D_CPU0_SB_DQ<20>")
	)
	(segment
		(start 343.13368 -232.250234)
		(end 343.13368 -231.714548)
		(width 0.20066)
		(layer "F.Cu")
		(net "M_D_CPU0_SB_DQ<20>")
	)
	(segment
		(start 263.624314 -207.51673)
		(end 262.255254 -207.51673)
		(width 0.20066)
		(layer "F.Cu")
		(net "M_D_CPU0_SB_DQ<20>")
	)
	(segment
		(start 259.056378 -207.08366)
		(end 258.49453 -207.08366)
		(width 0.20066)
		(layer "F.Cu")
		(net "M_D_CPU0_SB_DQ<20>")
	)
	(segment
		(start 262.255254 -207.51673)
		(end 261.830312 -207.091788)
		(width 0.20066)
		(layer "F.Cu")
		(net "M_D_CPU0_SB_DQ<20>")
	)
	(segment
		(start 264.729214 -207.51673)
		(end 263.624314 -207.51673)
		(width 0.20066)
		(layer "F.Cu")
		(net "M_D_CPU0_SB_DQ<20>")
	)
	(segment
		(start 259.31241 -207.091788)
		(end 259.064506 -207.091788)
		(width 0.101854)
		(layer "F.Cu")
		(net "M_D_CPU0_SB_DQ<20>")
	)
	(segment
		(start 270.811498 -207.586072)
		(end 270.811498 -207.253332)
		(width 0.18288)
		(layer "In6.Cu")
		(net "M_D_CPU0_SB_DQ<20>")
	)
	(segment
		(start 287.871916 -206.240888)
		(end 283.349954 -206.240888)
		(width 0.18288)
		(layer "In6.Cu")
		(net "M_D_CPU0_SB_DQ<20>")
	)
	(segment
		(start 281.325828 -207.092296)
		(end 279.729184 -207.092296)
		(width 0.18288)
		(layer "In6.Cu")
		(net "M_D_CPU0_SB_DQ<20>")
	)
	(segment
		(start 313.272424 -211.258404)
		(end 312.32729 -209.844132)
		(width 0.18288)
		(layer "In6.Cu")
		(net "M_D_CPU0_SB_DQ<20>")
	)
	(segment
		(start 290.015422 -207.085438)
		(end 289.784536 -206.854552)
		(width 0.18288)
		(layer "In6.Cu")
		(net "M_D_CPU0_SB_DQ<20>")
	)
	(segment
		(start 266.129516 -206.275432)
		(end 265.946636 -206.458312)
		(width 0.18288)
		(layer "In6.Cu")
		(net "M_D_CPU0_SB_DQ<20>")
	)
	(segment
		(start 338.33943 -230.91902)
		(end 338.33943 -230.891842)
		(width 0.088646)
		(layer "In6.Cu")
		(net "M_D_CPU0_SB_DQ<20>")
	)
	(segment
		(start 341.066882 -231.39019)
		(end 341.05215 -231.398826)
		(width 0.088646)
		(layer "In6.Cu")
		(net "M_D_CPU0_SB_DQ<20>")
	)
	(segment
		(start 307.323236 -208.760314)
		(end 303.766728 -208.760314)
		(width 0.18288)
		(layer "In6.Cu")
		(net "M_D_CPU0_SB_DQ<20>")
	)
	(segment
		(start 290.683442 -206.854552)
		(end 290.452556 -207.085438)
		(width 0.18288)
		(layer "In6.Cu")
		(net "M_D_CPU0_SB_DQ<20>")
	)
	(segment
		(start 271.344898 -207.746092)
		(end 270.971518 -207.746092)
		(width 0.18288)
		(layer "In6.Cu")
		(net "M_D_CPU0_SB_DQ<20>")
	)
	(segment
		(start 279.728168 -207.093312)
		(end 271.664938 -207.093312)
		(width 0.18288)
		(layer "In6.Cu")
		(net "M_D_CPU0_SB_DQ<20>")
	)
	(segment
		(start 330.895452 -227.849684)
		(end 330.41971 -227.849684)
		(width 0.088646)
		(layer "In6.Cu")
		(net "M_D_CPU0_SB_DQ<20>")
	)
	(segment
		(start 282.78582 -206.805022)
		(end 281.613102 -206.805022)
		(width 0.18288)
		(layer "In6.Cu")
		(net "M_D_CPU0_SB_DQ<20>")
	)
	(segment
		(start 270.971518 -207.746092)
		(end 270.811498 -207.586072)
		(width 0.18288)
		(layer "In6.Cu")
		(net "M_D_CPU0_SB_DQ<20>")
	)
	(segment
		(start 270.811498 -207.253332)
		(end 270.651478 -207.093312)
		(width 0.18288)
		(layer "In6.Cu")
		(net "M_D_CPU0_SB_DQ<20>")
	)
	(segment
		(start 313.498992 -211.805266)
		(end 313.272424 -211.258404)
		(width 0.18288)
		(layer "In6.Cu")
		(net "M_D_CPU0_SB_DQ<20>")
	)
	(segment
		(start 298.2849 -206.24165)
		(end 297.434254 -207.092296)
		(width 0.18288)
		(layer "In6.Cu")
		(net "M_D_CPU0_SB_DQ<20>")
	)
	(segment
		(start 334.110584 -230.10114)
		(end 334.11033 -230.086916)
		(width 0.088646)
		(layer "In6.Cu")
		(net "M_D_CPU0_SB_DQ<20>")
	)
	(segment
		(start 268.091666 -207.093312)
		(end 267.901928 -206.903574)
		(width 0.18288)
		(layer "In6.Cu")
		(net "M_D_CPU0_SB_DQ<20>")
	)
	(segment
		(start 331.74813 -229.518972)
		(end 331.74813 -228.702362)
		(width 0.088646)
		(layer "In6.Cu")
		(net "M_D_CPU0_SB_DQ<20>")
	)
	(segment
		(start 265.34237 -206.903574)
		(end 264.729214 -207.51673)
		(width 0.18288)
		(layer "In6.Cu")
		(net "M_D_CPU0_SB_DQ<20>")
	)
	(segment
		(start 279.729184 -207.092296)
		(end 279.728168 -207.093312)
		(width 0.18288)
		(layer "In6.Cu")
		(net "M_D_CPU0_SB_DQ<20>")
	)
	(segment
		(start 332.294992 -229.846632)
		(end 332.292706 -229.848918)
		(width 0.088646)
		(layer "In6.Cu")
		(net "M_D_CPU0_SB_DQ<20>")
	)
	(segment
		(start 266.637516 -206.720694)
		(end 266.637516 -206.458312)
		(width 0.18288)
		(layer "In6.Cu")
		(net "M_D_CPU0_SB_DQ<20>")
	)
	(segment
		(start 270.651478 -207.093312)
		(end 268.091666 -207.093312)
		(width 0.18288)
		(layer "In6.Cu")
		(net "M_D_CPU0_SB_DQ<20>")
	)
	(segment
		(start 265.946636 -206.458312)
		(end 265.946636 -206.720694)
		(width 0.18288)
		(layer "In6.Cu")
		(net "M_D_CPU0_SB_DQ<20>")
	)
	(segment
		(start 303.766728 -208.760314)
		(end 302.83404 -207.827626)
		(width 0.18288)
		(layer "In6.Cu")
		(net "M_D_CPU0_SB_DQ<20>")
	)
	(segment
		(start 266.454636 -206.275432)
		(end 266.129516 -206.275432)
		(width 0.18288)
		(layer "In6.Cu")
		(net "M_D_CPU0_SB_DQ<20>")
	)
	(segment
		(start 342.77808 -231.619298)
		(end 342.381332 -231.39019)
		(width 0.088646)
		(layer "In6.Cu")
		(net "M_D_CPU0_SB_DQ<20>")
	)
	(segment
		(start 266.820396 -206.903574)
		(end 266.637516 -206.720694)
		(width 0.18288)
		(layer "In6.Cu")
		(net "M_D_CPU0_SB_DQ<20>")
	)
	(segment
		(start 300.46676 -206.24165)
		(end 298.2849 -206.24165)
		(width 0.18288)
		(layer "In6.Cu")
		(net "M_D_CPU0_SB_DQ<20>")
	)
	(segment
		(start 267.901928 -206.903574)
		(end 266.820396 -206.903574)
		(width 0.18288)
		(layer "In6.Cu")
		(net "M_D_CPU0_SB_DQ<20>")
	)
	(segment
		(start 289.784536 -206.854552)
		(end 288.48558 -206.854552)
		(width 0.18288)
		(layer "In6.Cu")
		(net "M_D_CPU0_SB_DQ<20>")
	)
	(segment
		(start 266.637516 -206.458312)
		(end 266.454636 -206.275432)
		(width 0.18288)
		(layer "In6.Cu")
		(net "M_D_CPU0_SB_DQ<20>")
	)
	(segment
		(start 302.052736 -207.827626)
		(end 300.46676 -206.24165)
		(width 0.18288)
		(layer "In6.Cu")
		(net "M_D_CPU0_SB_DQ<20>")
	)
	(segment
		(start 271.664938 -207.093312)
		(end 271.504918 -207.253332)
		(width 0.18288)
		(layer "In6.Cu")
		(net "M_D_CPU0_SB_DQ<20>")
	)
	(segment
		(start 308.066948 -209.504026)
		(end 307.323236 -208.760314)
		(width 0.18288)
		(layer "In6.Cu")
		(net "M_D_CPU0_SB_DQ<20>")
	)
	(segment
		(start 271.504918 -207.253332)
		(end 271.504918 -207.586072)
		(width 0.18288)
		(layer "In6.Cu")
		(net "M_D_CPU0_SB_DQ<20>")
	)
	(segment
		(start 281.613102 -206.805022)
		(end 281.325828 -207.092296)
		(width 0.18288)
		(layer "In6.Cu")
		(net "M_D_CPU0_SB_DQ<20>")
	)
	(segment
		(start 340.127082 -231.39019)
		(end 340.11235 -231.398826)
		(width 0.088646)
		(layer "In6.Cu")
		(net "M_D_CPU0_SB_DQ<20>")
	)
	(segment
		(start 331.74813 -228.702362)
		(end 330.895452 -227.849684)
		(width 0.088646)
		(layer "In6.Cu")
		(net "M_D_CPU0_SB_DQ<20>")
	)
	(segment
		(start 314.597796 -212.90407)
		(end 313.498992 -211.805266)
		(width 0.18288)
		(layer "In6.Cu")
		(net "M_D_CPU0_SB_DQ<20>")
	)
	(segment
		(start 337.227164 -230.584756)
		(end 337.212432 -230.57612)
		(width 0.088646)
		(layer "In6.Cu")
		(net "M_D_CPU0_SB_DQ<20>")
	)
	(segment
		(start 312.32729 -209.844132)
		(end 311.987184 -209.504026)
		(width 0.18288)
		(layer "In6.Cu")
		(net "M_D_CPU0_SB_DQ<20>")
	)
	(segment
		(start 314.965334 -213.791292)
		(end 314.597796 -212.90407)
		(width 0.18288)
		(layer "In6.Cu")
		(net "M_D_CPU0_SB_DQ<20>")
	)
	(segment
		(start 334.407764 -230.58501)
		(end 334.393032 -230.576374)
		(width 0.088646)
		(layer "In6.Cu")
		(net "M_D_CPU0_SB_DQ<20>")
	)
	(segment
		(start 330.41971 -227.849684)
		(end 326.347582 -227.849684)
		(width 0.18288)
		(layer "In6.Cu")
		(net "M_D_CPU0_SB_DQ<20>")
	)
	(segment
		(start 265.763756 -206.903574)
		(end 265.34237 -206.903574)
		(width 0.18288)
		(layer "In6.Cu")
		(net "M_D_CPU0_SB_DQ<20>")
	)
	(segment
		(start 297.434254 -207.092296)
		(end 291.92728 -207.092296)
		(width 0.18288)
		(layer "In6.Cu")
		(net "M_D_CPU0_SB_DQ<20>")
	)
	(segment
		(start 291.92728 -207.092296)
		(end 291.689536 -206.854552)
		(width 0.18288)
		(layer "In6.Cu")
		(net "M_D_CPU0_SB_DQ<20>")
	)
	(segment
		(start 323.368924 -222.194882)
		(end 314.965334 -213.791292)
		(width 0.18288)
		(layer "In6.Cu")
		(net "M_D_CPU0_SB_DQ<20>")
	)
	(segment
		(start 288.48558 -206.854552)
		(end 287.871916 -206.240888)
		(width 0.18288)
		(layer "In6.Cu")
		(net "M_D_CPU0_SB_DQ<20>")
	)
	(segment
		(start 311.987184 -209.504026)
		(end 308.066948 -209.504026)
		(width 0.18288)
		(layer "In6.Cu")
		(net "M_D_CPU0_SB_DQ<20>")
	)
	(segment
		(start 265.946636 -206.720694)
		(end 265.763756 -206.903574)
		(width 0.18288)
		(layer "In6.Cu")
		(net "M_D_CPU0_SB_DQ<20>")
	)
	(segment
		(start 290.452556 -207.085438)
		(end 290.015422 -207.085438)
		(width 0.18288)
		(layer "In6.Cu")
		(net "M_D_CPU0_SB_DQ<20>")
	)
	(segment
		(start 271.504918 -207.586072)
		(end 271.344898 -207.746092)
		(width 0.18288)
		(layer "In6.Cu")
		(net "M_D_CPU0_SB_DQ<20>")
	)
	(segment
		(start 335.909158 -230.570024)
		(end 335.898236 -230.576374)
		(width 0.088646)
		(layer "In6.Cu")
		(net "M_D_CPU0_SB_DQ<20>")
	)
	(segment
		(start 291.689536 -206.854552)
		(end 290.683442 -206.854552)
		(width 0.18288)
		(layer "In6.Cu")
		(net "M_D_CPU0_SB_DQ<20>")
	)
	(segment
		(start 326.347582 -227.849684)
		(end 323.368924 -224.871026)
		(width 0.18288)
		(layer "In6.Cu")
		(net "M_D_CPU0_SB_DQ<20>")
	)
	(segment
		(start 336.287364 -230.584756)
		(end 336.272632 -230.57612)
		(width 0.088646)
		(layer "In6.Cu")
		(net "M_D_CPU0_SB_DQ<20>")
	)
	(segment
		(start 332.078076 -229.848918)
		(end 331.74813 -229.518972)
		(width 0.088646)
		(layer "In6.Cu")
		(net "M_D_CPU0_SB_DQ<20>")
	)
	(segment
		(start 334.11033 -230.086916)
		(end 334.11033 -230.07828)
		(width 0.088646)
		(layer "In6.Cu")
		(net "M_D_CPU0_SB_DQ<20>")
	)
	(segment
		(start 283.349954 -206.240888)
		(end 282.78582 -206.805022)
		(width 0.18288)
		(layer "In6.Cu")
		(net "M_D_CPU0_SB_DQ<20>")
	)
	(segment
		(start 332.292706 -229.848918)
		(end 332.078076 -229.848918)
		(width 0.088646)
		(layer "In6.Cu")
		(net "M_D_CPU0_SB_DQ<20>")
	)
	(segment
		(start 342.006936 -231.39019)
		(end 341.996522 -231.396286)
		(width 0.088646)
		(layer "In6.Cu")
		(net "M_D_CPU0_SB_DQ<20>")
	)
	(segment
		(start 302.83404 -207.827626)
		(end 302.052736 -207.827626)
		(width 0.18288)
		(layer "In6.Cu")
		(net "M_D_CPU0_SB_DQ<20>")
	)
	(segment
		(start 323.368924 -224.871026)
		(end 323.368924 -222.194882)
		(width 0.18288)
		(layer "In6.Cu")
		(net "M_D_CPU0_SB_DQ<20>")
	)
	(arc
		(start 335.332832 -230.576374)
		(mid 335.145634 -230.526231)
		(end 334.958436 -230.576374)
		(width 0.088646)
		(layer "In6.Cu")
		(net "M_D_CPU0_SB_DQ<20>")
	)
	(arc
		(start 340.501478 -231.39019)
		(mid 340.31428 -231.340047)
		(end 340.127082 -231.39019)
		(width 0.088646)
		(layer "In6.Cu")
		(net "M_D_CPU0_SB_DQ<20>")
	)
	(arc
		(start 332.608936 -229.762558)
		(mid 332.457496 -229.825255)
		(end 332.294992 -229.846632)
		(width 0.088646)
		(layer "In6.Cu")
		(net "M_D_CPU0_SB_DQ<20>")
	)
	(arc
		(start 337.212432 -230.57612)
		(mid 337.025234 -230.525977)
		(end 336.838036 -230.57612)
		(width 0.088646)
		(layer "In6.Cu")
		(net "M_D_CPU0_SB_DQ<20>")
	)
	(arc
		(start 339.561678 -231.39019)
		(mid 339.37448 -231.340047)
		(end 339.187282 -231.39019)
		(width 0.088646)
		(layer "In6.Cu")
		(net "M_D_CPU0_SB_DQ<20>")
	)
	(arc
		(start 338.621878 -231.39019)
		(mid 338.419592 -231.191209)
		(end 338.33943 -230.91902)
		(width 0.088646)
		(layer "In6.Cu")
		(net "M_D_CPU0_SB_DQ<20>")
	)
	(arc
		(start 339.187282 -231.39019)
		(mid 338.90458 -231.465932)
		(end 338.621878 -231.39019)
		(width 0.088646)
		(layer "In6.Cu")
		(net "M_D_CPU0_SB_DQ<20>")
	)
	(arc
		(start 341.996522 -231.396286)
		(mid 341.71809 -231.4661)
		(end 341.441278 -231.39019)
		(width 0.088646)
		(layer "In6.Cu")
		(net "M_D_CPU0_SB_DQ<20>")
	)
	(arc
		(start 334.11033 -230.07828)
		(mid 334.05806 -229.895915)
		(end 333.923132 -229.762558)
		(width 0.088646)
		(layer "In6.Cu")
		(net "M_D_CPU0_SB_DQ<20>")
	)
	(arc
		(start 336.272632 -230.57612)
		(mid 336.091688 -230.526029)
		(end 335.909158 -230.570024)
		(width 0.088646)
		(layer "In6.Cu")
		(net "M_D_CPU0_SB_DQ<20>")
	)
	(arc
		(start 334.393032 -230.576374)
		(mid 334.189796 -230.375627)
		(end 334.110584 -230.10114)
		(width 0.088646)
		(layer "In6.Cu")
		(net "M_D_CPU0_SB_DQ<20>")
	)
	(arc
		(start 338.152232 -230.57612)
		(mid 337.965034 -230.525977)
		(end 337.777836 -230.57612)
		(width 0.088646)
		(layer "In6.Cu")
		(net "M_D_CPU0_SB_DQ<20>")
	)
	(arc
		(start 341.441278 -231.39019)
		(mid 341.25408 -231.340047)
		(end 341.066882 -231.39019)
		(width 0.088646)
		(layer "In6.Cu")
		(net "M_D_CPU0_SB_DQ<20>")
	)
	(arc
		(start 343.13368 -231.714548)
		(mid 342.949628 -231.690279)
		(end 342.77808 -231.619298)
		(width 0.088646)
		(layer "In6.Cu")
		(net "M_D_CPU0_SB_DQ<20>")
	)
	(arc
		(start 336.838036 -230.57612)
		(mid 336.563837 -230.651955)
		(end 336.287364 -230.584756)
		(width 0.088646)
		(layer "In6.Cu")
		(net "M_D_CPU0_SB_DQ<20>")
	)
	(arc
		(start 333.548736 -229.762558)
		(mid 333.266034 -229.838334)
		(end 332.983332 -229.762558)
		(width 0.088646)
		(layer "In6.Cu")
		(net "M_D_CPU0_SB_DQ<20>")
	)
	(arc
		(start 334.958436 -230.576374)
		(mid 334.684207 -230.652299)
		(end 334.407764 -230.58501)
		(width 0.088646)
		(layer "In6.Cu")
		(net "M_D_CPU0_SB_DQ<20>")
	)
	(arc
		(start 341.05215 -231.398826)
		(mid 340.775709 -231.465992)
		(end 340.501478 -231.39019)
		(width 0.088646)
		(layer "In6.Cu")
		(net "M_D_CPU0_SB_DQ<20>")
	)
	(arc
		(start 338.33943 -230.891842)
		(mid 338.28716 -230.709477)
		(end 338.152232 -230.57612)
		(width 0.088646)
		(layer "In6.Cu")
		(net "M_D_CPU0_SB_DQ<20>")
	)
	(arc
		(start 337.777836 -230.57612)
		(mid 337.503637 -230.651955)
		(end 337.227164 -230.584756)
		(width 0.088646)
		(layer "In6.Cu")
		(net "M_D_CPU0_SB_DQ<20>")
	)
	(arc
		(start 335.898236 -230.576374)
		(mid 335.615534 -230.65215)
		(end 335.332832 -230.576374)
		(width 0.088646)
		(layer "In6.Cu")
		(net "M_D_CPU0_SB_DQ<20>")
	)
	(arc
		(start 342.381332 -231.39019)
		(mid 342.194134 -231.340047)
		(end 342.006936 -231.39019)
		(width 0.088646)
		(layer "In6.Cu")
		(net "M_D_CPU0_SB_DQ<20>")
	)
	(arc
		(start 333.923132 -229.762558)
		(mid 333.735934 -229.712415)
		(end 333.548736 -229.762558)
		(width 0.088646)
		(layer "In6.Cu")
		(net "M_D_CPU0_SB_DQ<20>")
	)
	(arc
		(start 340.11235 -231.398826)
		(mid 339.835909 -231.465992)
		(end 339.561678 -231.39019)
		(width 0.088646)
		(layer "In6.Cu")
		(net "M_D_CPU0_SB_DQ<20>")
	)
	(arc
		(start 332.983332 -229.762558)
		(mid 332.796134 -229.712415)
		(end 332.608936 -229.762558)
		(width 0.088646)
		(layer "In6.Cu")
		(net "M_D_CPU0_SB_DQ<20>")
	)
	(segment
		(start 263.624314 -230.466646)
		(end 261.984998 -230.466646)
		(width 0.20066)
		(layer "F.Cu")
		(net "M_D_CPU0_SB_DQ<1>")
	)
	(segment
		(start 261.984998 -230.466646)
		(end 261.560056 -230.041704)
		(width 0.20066)
		(layer "F.Cu")
		(net "M_D_CPU0_SB_DQ<1>")
	)
	(segment
		(start 258.28498 -230.195374)
		(end 258.28498 -230.523542)
		(width 0.20066)
		(layer "F.Cu")
		(net "M_D_CPU0_SB_DQ<1>")
	)
	(segment
		(start 258.28498 -230.523542)
		(end 258.130548 -230.677974)
		(width 0.20066)
		(layer "F.Cu")
		(net "M_D_CPU0_SB_DQ<1>")
	)
	(segment
		(start 261.381494 -230.041704)
		(end 261.050786 -230.041704)
		(width 0.101854)
		(layer "F.Cu")
		(net "M_D_CPU0_SB_DQ<1>")
	)
	(segment
		(start 257.626104 -230.677974)
		(end 257.414776 -230.466646)
		(width 0.20066)
		(layer "F.Cu")
		(net "M_D_CPU0_SB_DQ<1>")
	)
	(segment
		(start 346.42298 -241.203226)
		(end 346.423234 -241.202972)
		(width 0.20066)
		(layer "F.Cu")
		(net "M_D_CPU0_SB_DQ<1>")
	)
	(segment
		(start 261.050786 -230.041704)
		(end 259.065268 -230.041704)
		(width 0.1016)
		(layer "F.Cu")
		(net "M_D_CPU0_SB_DQ<1>")
	)
	(segment
		(start 257.414776 -230.466646)
		(end 256.080514 -230.466646)
		(width 0.20066)
		(layer "F.Cu")
		(net "M_D_CPU0_SB_DQ<1>")
	)
	(segment
		(start 259.065268 -230.041704)
		(end 259.056378 -230.032814)
		(width 0.1016)
		(layer "F.Cu")
		(net "M_D_CPU0_SB_DQ<1>")
	)
	(segment
		(start 259.056378 -230.032814)
		(end 258.44754 -230.032814)
		(width 0.20066)
		(layer "F.Cu")
		(net "M_D_CPU0_SB_DQ<1>")
	)
	(segment
		(start 258.130548 -230.677974)
		(end 257.626104 -230.677974)
		(width 0.20066)
		(layer "F.Cu")
		(net "M_D_CPU0_SB_DQ<1>")
	)
	(segment
		(start 264.729214 -230.466646)
		(end 263.624314 -230.466646)
		(width 0.20066)
		(layer "F.Cu")
		(net "M_D_CPU0_SB_DQ<1>")
	)
	(segment
		(start 346.423234 -241.202972)
		(end 346.423234 -240.667286)
		(width 0.20066)
		(layer "F.Cu")
		(net "M_D_CPU0_SB_DQ<1>")
	)
	(segment
		(start 261.560056 -230.041704)
		(end 261.381494 -230.041704)
		(width 0.20066)
		(layer "F.Cu")
		(net "M_D_CPU0_SB_DQ<1>")
	)
	(segment
		(start 258.44754 -230.032814)
		(end 258.28498 -230.195374)
		(width 0.20066)
		(layer "F.Cu")
		(net "M_D_CPU0_SB_DQ<1>")
	)
	(segment
		(start 340.127082 -241.156744)
		(end 340.11235 -241.16538)
		(width 0.088646)
		(layer "In11.Cu")
		(net "M_D_CPU0_SB_DQ<1>")
	)
	(segment
		(start 267.643864 -229.453186)
		(end 267.054076 -229.453186)
		(width 0.18288)
		(layer "In11.Cu")
		(net "M_D_CPU0_SB_DQ<1>")
	)
	(segment
		(start 273.151346 -230.728774)
		(end 269.339314 -230.728774)
		(width 0.18288)
		(layer "In11.Cu")
		(net "M_D_CPU0_SB_DQ<1>")
	)
	(segment
		(start 282.459938 -227.49256)
		(end 279.210008 -227.49256)
		(width 0.18288)
		(layer "In11.Cu")
		(net "M_D_CPU0_SB_DQ<1>")
	)
	(segment
		(start 274.106894 -229.722426)
		(end 273.814794 -230.014526)
		(width 0.18288)
		(layer "In11.Cu")
		(net "M_D_CPU0_SB_DQ<1>")
	)
	(segment
		(start 299.811694 -226.522026)
		(end 299.691298 -226.642422)
		(width 0.18288)
		(layer "In11.Cu")
		(net "M_D_CPU0_SB_DQ<1>")
	)
	(segment
		(start 307.770022 -228.173026)
		(end 305.323494 -228.173026)
		(width 0.18288)
		(layer "In11.Cu")
		(net "M_D_CPU0_SB_DQ<1>")
	)
	(segment
		(start 342.946482 -241.156744)
		(end 342.936068 -241.16284)
		(width 0.088646)
		(layer "In11.Cu")
		(net "M_D_CPU0_SB_DQ<1>")
	)
	(segment
		(start 314.867036 -231.070912)
		(end 314.434728 -230.892096)
		(width 0.18288)
		(layer "In11.Cu")
		(net "M_D_CPU0_SB_DQ<1>")
	)
	(segment
		(start 342.006936 -241.156744)
		(end 341.996522 -241.16284)
		(width 0.088646)
		(layer "In11.Cu")
		(net "M_D_CPU0_SB_DQ<1>")
	)
	(segment
		(start 287.550352 -226.528884)
		(end 284.793436 -226.528884)
		(width 0.18288)
		(layer "In11.Cu")
		(net "M_D_CPU0_SB_DQ<1>")
	)
	(segment
		(start 299.691298 -226.642422)
		(end 298.397676 -226.642422)
		(width 0.18288)
		(layer "In11.Cu")
		(net "M_D_CPU0_SB_DQ<1>")
	)
	(segment
		(start 274.614894 -229.722426)
		(end 274.106894 -229.722426)
		(width 0.18288)
		(layer "In11.Cu")
		(net "M_D_CPU0_SB_DQ<1>")
	)
	(segment
		(start 265.371834 -229.824026)
		(end 264.729214 -230.466646)
		(width 0.18288)
		(layer "In11.Cu")
		(net "M_D_CPU0_SB_DQ<1>")
	)
	(segment
		(start 344.826082 -241.156744)
		(end 344.81135 -241.16538)
		(width 0.088646)
		(layer "In11.Cu")
		(net "M_D_CPU0_SB_DQ<1>")
	)
	(segment
		(start 273.814794 -230.065326)
		(end 273.151346 -230.728774)
		(width 0.18288)
		(layer "In11.Cu")
		(net "M_D_CPU0_SB_DQ<1>")
	)
	(segment
		(start 266.683236 -229.824026)
		(end 265.371834 -229.824026)
		(width 0.18288)
		(layer "In11.Cu")
		(net "M_D_CPU0_SB_DQ<1>")
	)
	(segment
		(start 322.25615 -238.444786)
		(end 314.867036 -231.070912)
		(width 0.18288)
		(layer "In11.Cu")
		(net "M_D_CPU0_SB_DQ<1>")
	)
	(segment
		(start 288.483294 -227.461826)
		(end 287.550352 -226.528884)
		(width 0.18288)
		(layer "In11.Cu")
		(net "M_D_CPU0_SB_DQ<1>")
	)
	(segment
		(start 269.339314 -230.728774)
		(end 269.177262 -230.890826)
		(width 0.18288)
		(layer "In11.Cu")
		(net "M_D_CPU0_SB_DQ<1>")
	)
	(segment
		(start 289.887914 -227.461826)
		(end 288.483294 -227.461826)
		(width 0.18288)
		(layer "In11.Cu")
		(net "M_D_CPU0_SB_DQ<1>")
	)
	(segment
		(start 267.971016 -230.540306)
		(end 267.971016 -229.780338)
		(width 0.18288)
		(layer "In11.Cu")
		(net "M_D_CPU0_SB_DQ<1>")
	)
	(segment
		(start 332.079854 -239.60455)
		(end 330.92009 -238.444786)
		(width 0.088646)
		(layer "In11.Cu")
		(net "M_D_CPU0_SB_DQ<1>")
	)
	(segment
		(start 302.834294 -226.522026)
		(end 299.811694 -226.522026)
		(width 0.18288)
		(layer "In11.Cu")
		(net "M_D_CPU0_SB_DQ<1>")
	)
	(segment
		(start 332.326488 -239.60455)
		(end 332.079854 -239.60455)
		(width 0.088646)
		(layer "In11.Cu")
		(net "M_D_CPU0_SB_DQ<1>")
	)
	(segment
		(start 314.434728 -230.892096)
		(end 313.528964 -230.892096)
		(width 0.18288)
		(layer "In11.Cu")
		(net "M_D_CPU0_SB_DQ<1>")
	)
	(segment
		(start 335.520284 -240.677192)
		(end 335.520284 -240.667286)
		(width 0.088646)
		(layer "In11.Cu")
		(net "M_D_CPU0_SB_DQ<1>")
	)
	(segment
		(start 283.310076 -226.642422)
		(end 282.459938 -227.49256)
		(width 0.18288)
		(layer "In11.Cu")
		(net "M_D_CPU0_SB_DQ<1>")
	)
	(segment
		(start 293.666418 -228.12375)
		(end 290.549838 -228.12375)
		(width 0.18288)
		(layer "In11.Cu")
		(net "M_D_CPU0_SB_DQ<1>")
	)
	(segment
		(start 345.84513 -241.111024)
		(end 345.765882 -241.156744)
		(width 0.088646)
		(layer "In11.Cu")
		(net "M_D_CPU0_SB_DQ<1>")
	)
	(segment
		(start 267.054076 -229.453186)
		(end 266.683236 -229.824026)
		(width 0.18288)
		(layer "In11.Cu")
		(net "M_D_CPU0_SB_DQ<1>")
	)
	(segment
		(start 334.11033 -239.86744)
		(end 334.11033 -239.853216)
		(width 0.088646)
		(layer "In11.Cu")
		(net "M_D_CPU0_SB_DQ<1>")
	)
	(segment
		(start 297.547538 -227.49256)
		(end 294.297608 -227.49256)
		(width 0.18288)
		(layer "In11.Cu")
		(net "M_D_CPU0_SB_DQ<1>")
	)
	(segment
		(start 303.659032 -227.346764)
		(end 302.834294 -226.522026)
		(width 0.18288)
		(layer "In11.Cu")
		(net "M_D_CPU0_SB_DQ<1>")
	)
	(segment
		(start 333.931768 -239.533938)
		(end 333.922878 -239.528858)
		(width 0.088646)
		(layer "In11.Cu")
		(net "M_D_CPU0_SB_DQ<1>")
	)
	(segment
		(start 336.367882 -241.156744)
		(end 336.357468 -241.16284)
		(width 0.088646)
		(layer "In11.Cu")
		(net "M_D_CPU0_SB_DQ<1>")
	)
	(segment
		(start 276.494494 -229.341426)
		(end 274.995894 -229.341426)
		(width 0.18288)
		(layer "In11.Cu")
		(net "M_D_CPU0_SB_DQ<1>")
	)
	(segment
		(start 313.528964 -230.892096)
		(end 312.676794 -230.039926)
		(width 0.18288)
		(layer "In11.Cu")
		(net "M_D_CPU0_SB_DQ<1>")
	)
	(segment
		(start 269.177262 -230.890826)
		(end 268.321536 -230.890826)
		(width 0.18288)
		(layer "In11.Cu")
		(net "M_D_CPU0_SB_DQ<1>")
	)
	(segment
		(start 335.341722 -240.348008)
		(end 335.332832 -240.342928)
		(width 0.088646)
		(layer "In11.Cu")
		(net "M_D_CPU0_SB_DQ<1>")
	)
	(segment
		(start 273.814794 -230.014526)
		(end 273.814794 -230.065326)
		(width 0.18288)
		(layer "In11.Cu")
		(net "M_D_CPU0_SB_DQ<1>")
	)
	(segment
		(start 330.92009 -238.444786)
		(end 330.313538 -238.444786)
		(width 0.088646)
		(layer "In11.Cu")
		(net "M_D_CPU0_SB_DQ<1>")
	)
	(segment
		(start 290.549838 -228.12375)
		(end 289.887914 -227.461826)
		(width 0.18288)
		(layer "In11.Cu")
		(net "M_D_CPU0_SB_DQ<1>")
	)
	(segment
		(start 267.971016 -229.780338)
		(end 267.643864 -229.453186)
		(width 0.18288)
		(layer "In11.Cu")
		(net "M_D_CPU0_SB_DQ<1>")
	)
	(segment
		(start 274.995894 -229.341426)
		(end 274.614894 -229.722426)
		(width 0.18288)
		(layer "In11.Cu")
		(net "M_D_CPU0_SB_DQ<1>")
	)
	(segment
		(start 278.504142 -228.198426)
		(end 277.637494 -228.198426)
		(width 0.18288)
		(layer "In11.Cu")
		(net "M_D_CPU0_SB_DQ<1>")
	)
	(segment
		(start 284.793436 -226.528884)
		(end 284.679898 -226.642422)
		(width 0.18288)
		(layer "In11.Cu")
		(net "M_D_CPU0_SB_DQ<1>")
	)
	(segment
		(start 312.676794 -230.039926)
		(end 309.636922 -230.039926)
		(width 0.18288)
		(layer "In11.Cu")
		(net "M_D_CPU0_SB_DQ<1>")
	)
	(segment
		(start 334.407764 -240.351564)
		(end 334.393032 -240.342928)
		(width 0.088646)
		(layer "In11.Cu")
		(net "M_D_CPU0_SB_DQ<1>")
	)
	(segment
		(start 330.313538 -238.444786)
		(end 322.25615 -238.444786)
		(width 0.18288)
		(layer "In11.Cu")
		(net "M_D_CPU0_SB_DQ<1>")
	)
	(segment
		(start 284.679898 -226.642422)
		(end 283.310076 -226.642422)
		(width 0.18288)
		(layer "In11.Cu")
		(net "M_D_CPU0_SB_DQ<1>")
	)
	(segment
		(start 279.210008 -227.49256)
		(end 278.504142 -228.198426)
		(width 0.18288)
		(layer "In11.Cu")
		(net "M_D_CPU0_SB_DQ<1>")
	)
	(segment
		(start 268.321536 -230.890826)
		(end 267.971016 -230.540306)
		(width 0.18288)
		(layer "In11.Cu")
		(net "M_D_CPU0_SB_DQ<1>")
	)
	(segment
		(start 337.307682 -241.156744)
		(end 337.29295 -241.16538)
		(width 0.088646)
		(layer "In11.Cu")
		(net "M_D_CPU0_SB_DQ<1>")
	)
	(segment
		(start 277.637494 -228.198426)
		(end 276.494494 -229.341426)
		(width 0.18288)
		(layer "In11.Cu")
		(net "M_D_CPU0_SB_DQ<1>")
	)
	(segment
		(start 305.323494 -228.173026)
		(end 304.497232 -227.346764)
		(width 0.18288)
		(layer "In11.Cu")
		(net "M_D_CPU0_SB_DQ<1>")
	)
	(segment
		(start 338.247482 -241.156744)
		(end 338.23275 -241.16538)
		(width 0.088646)
		(layer "In11.Cu")
		(net "M_D_CPU0_SB_DQ<1>")
	)
	(segment
		(start 343.886282 -241.156744)
		(end 343.87155 -241.16538)
		(width 0.088646)
		(layer "In11.Cu")
		(net "M_D_CPU0_SB_DQ<1>")
	)
	(segment
		(start 294.297608 -227.49256)
		(end 293.666418 -228.12375)
		(width 0.18288)
		(layer "In11.Cu")
		(net "M_D_CPU0_SB_DQ<1>")
	)
	(segment
		(start 304.497232 -227.346764)
		(end 303.659032 -227.346764)
		(width 0.18288)
		(layer "In11.Cu")
		(net "M_D_CPU0_SB_DQ<1>")
	)
	(segment
		(start 333.548482 -239.528858)
		(end 333.53375 -239.537494)
		(width 0.088646)
		(layer "In11.Cu")
		(net "M_D_CPU0_SB_DQ<1>")
	)
	(segment
		(start 309.636922 -230.039926)
		(end 307.770022 -228.173026)
		(width 0.18288)
		(layer "In11.Cu")
		(net "M_D_CPU0_SB_DQ<1>")
	)
	(segment
		(start 341.066882 -241.156744)
		(end 341.05215 -241.16538)
		(width 0.088646)
		(layer "In11.Cu")
		(net "M_D_CPU0_SB_DQ<1>")
	)
	(segment
		(start 298.397676 -226.642422)
		(end 297.547538 -227.49256)
		(width 0.18288)
		(layer "In11.Cu")
		(net "M_D_CPU0_SB_DQ<1>")
	)
	(arc
		(start 342.381332 -241.156744)
		(mid 342.194134 -241.106601)
		(end 342.006936 -241.156744)
		(width 0.088646)
		(layer "In11.Cu")
		(net "M_D_CPU0_SB_DQ<1>")
	)
	(arc
		(start 341.05215 -241.16538)
		(mid 340.775675 -241.2327)
		(end 340.501478 -241.156744)
		(width 0.088646)
		(layer "In11.Cu")
		(net "M_D_CPU0_SB_DQ<1>")
	)
	(arc
		(start 337.29295 -241.16538)
		(mid 337.016475 -241.2327)
		(end 336.742278 -241.156744)
		(width 0.088646)
		(layer "In11.Cu")
		(net "M_D_CPU0_SB_DQ<1>")
	)
	(arc
		(start 340.501478 -241.156744)
		(mid 340.31428 -241.106601)
		(end 340.127082 -241.156744)
		(width 0.088646)
		(layer "In11.Cu")
		(net "M_D_CPU0_SB_DQ<1>")
	)
	(arc
		(start 339.561678 -241.156744)
		(mid 339.37448 -241.106601)
		(end 339.187282 -241.156744)
		(width 0.088646)
		(layer "In11.Cu")
		(net "M_D_CPU0_SB_DQ<1>")
	)
	(arc
		(start 335.520284 -240.667286)
		(mid 335.472605 -240.484386)
		(end 335.341722 -240.348008)
		(width 0.088646)
		(layer "In11.Cu")
		(net "M_D_CPU0_SB_DQ<1>")
	)
	(arc
		(start 346.423234 -240.667286)
		(mid 346.148714 -240.908088)
		(end 345.84513 -241.111024)
		(width 0.088646)
		(layer "In11.Cu")
		(net "M_D_CPU0_SB_DQ<1>")
	)
	(arc
		(start 332.608682 -239.528858)
		(mid 332.490051 -239.580378)
		(end 332.36281 -239.603534)
		(width 0.088646)
		(layer "In11.Cu")
		(net "M_D_CPU0_SB_DQ<1>")
	)
	(arc
		(start 343.87155 -241.16538)
		(mid 343.595075 -241.2327)
		(end 343.320878 -241.156744)
		(width 0.088646)
		(layer "In11.Cu")
		(net "M_D_CPU0_SB_DQ<1>")
	)
	(arc
		(start 345.200478 -241.156744)
		(mid 345.01328 -241.106601)
		(end 344.826082 -241.156744)
		(width 0.088646)
		(layer "In11.Cu")
		(net "M_D_CPU0_SB_DQ<1>")
	)
	(arc
		(start 337.682078 -241.156744)
		(mid 337.49488 -241.106601)
		(end 337.307682 -241.156744)
		(width 0.088646)
		(layer "In11.Cu")
		(net "M_D_CPU0_SB_DQ<1>")
	)
	(arc
		(start 333.53375 -239.537494)
		(mid 333.257275 -239.604814)
		(end 332.983078 -239.528858)
		(width 0.088646)
		(layer "In11.Cu")
		(net "M_D_CPU0_SB_DQ<1>")
	)
	(arc
		(start 332.983078 -239.528858)
		(mid 332.79588 -239.478715)
		(end 332.608682 -239.528858)
		(width 0.088646)
		(layer "In11.Cu")
		(net "M_D_CPU0_SB_DQ<1>")
	)
	(arc
		(start 334.958436 -240.342928)
		(mid 334.684207 -240.418853)
		(end 334.407764 -240.351564)
		(width 0.088646)
		(layer "In11.Cu")
		(net "M_D_CPU0_SB_DQ<1>")
	)
	(arc
		(start 344.260678 -241.156744)
		(mid 344.07348 -241.106601)
		(end 343.886282 -241.156744)
		(width 0.088646)
		(layer "In11.Cu")
		(net "M_D_CPU0_SB_DQ<1>")
	)
	(arc
		(start 336.357468 -241.16284)
		(mid 336.07929 -241.232563)
		(end 335.802732 -241.156744)
		(width 0.088646)
		(layer "In11.Cu")
		(net "M_D_CPU0_SB_DQ<1>")
	)
	(arc
		(start 341.996522 -241.16284)
		(mid 341.71809 -241.232686)
		(end 341.441278 -241.156744)
		(width 0.088646)
		(layer "In11.Cu")
		(net "M_D_CPU0_SB_DQ<1>")
	)
	(arc
		(start 333.922878 -239.528858)
		(mid 333.73568 -239.478715)
		(end 333.548482 -239.528858)
		(width 0.088646)
		(layer "In11.Cu")
		(net "M_D_CPU0_SB_DQ<1>")
	)
	(arc
		(start 335.332832 -240.342928)
		(mid 335.145634 -240.292785)
		(end 334.958436 -240.342928)
		(width 0.088646)
		(layer "In11.Cu")
		(net "M_D_CPU0_SB_DQ<1>")
	)
	(arc
		(start 338.23275 -241.16538)
		(mid 337.956275 -241.2327)
		(end 337.682078 -241.156744)
		(width 0.088646)
		(layer "In11.Cu")
		(net "M_D_CPU0_SB_DQ<1>")
	)
	(arc
		(start 343.320878 -241.156744)
		(mid 343.13368 -241.106601)
		(end 342.946482 -241.156744)
		(width 0.088646)
		(layer "In11.Cu")
		(net "M_D_CPU0_SB_DQ<1>")
	)
	(arc
		(start 341.441278 -241.156744)
		(mid 341.25408 -241.106601)
		(end 341.066882 -241.156744)
		(width 0.088646)
		(layer "In11.Cu")
		(net "M_D_CPU0_SB_DQ<1>")
	)
	(arc
		(start 345.765882 -241.156744)
		(mid 345.48318 -241.23252)
		(end 345.200478 -241.156744)
		(width 0.088646)
		(layer "In11.Cu")
		(net "M_D_CPU0_SB_DQ<1>")
	)
	(arc
		(start 338.621878 -241.156744)
		(mid 338.43468 -241.106601)
		(end 338.247482 -241.156744)
		(width 0.088646)
		(layer "In11.Cu")
		(net "M_D_CPU0_SB_DQ<1>")
	)
	(arc
		(start 339.187282 -241.156744)
		(mid 338.90458 -241.23252)
		(end 338.621878 -241.156744)
		(width 0.088646)
		(layer "In11.Cu")
		(net "M_D_CPU0_SB_DQ<1>")
	)
	(arc
		(start 344.81135 -241.16538)
		(mid 344.534875 -241.2327)
		(end 344.260678 -241.156744)
		(width 0.088646)
		(layer "In11.Cu")
		(net "M_D_CPU0_SB_DQ<1>")
	)
	(arc
		(start 334.393032 -240.342928)
		(mid 334.189551 -240.142124)
		(end 334.11033 -239.86744)
		(width 0.088646)
		(layer "In11.Cu")
		(net "M_D_CPU0_SB_DQ<1>")
	)
	(arc
		(start 335.802732 -241.156744)
		(mid 335.598397 -240.954139)
		(end 335.520284 -240.677192)
		(width 0.088646)
		(layer "In11.Cu")
		(net "M_D_CPU0_SB_DQ<1>")
	)
	(arc
		(start 340.11235 -241.16538)
		(mid 339.835875 -241.2327)
		(end 339.561678 -241.156744)
		(width 0.088646)
		(layer "In11.Cu")
		(net "M_D_CPU0_SB_DQ<1>")
	)
	(arc
		(start 334.11033 -239.853216)
		(mid 334.062651 -239.670316)
		(end 333.931768 -239.533938)
		(width 0.088646)
		(layer "In11.Cu")
		(net "M_D_CPU0_SB_DQ<1>")
	)
	(arc
		(start 336.742278 -241.156744)
		(mid 336.55508 -241.106601)
		(end 336.367882 -241.156744)
		(width 0.088646)
		(layer "In11.Cu")
		(net "M_D_CPU0_SB_DQ<1>")
	)
	(arc
		(start 332.36281 -239.603534)
		(mid 332.344657 -239.604337)
		(end 332.326488 -239.60455)
		(width 0.088646)
		(layer "In11.Cu")
		(net "M_D_CPU0_SB_DQ<1>")
	)
	(arc
		(start 342.936068 -241.16284)
		(mid 342.65789 -241.232563)
		(end 342.381332 -241.156744)
		(width 0.088646)
		(layer "In11.Cu")
		(net "M_D_CPU0_SB_DQ<1>")
	)
	(segment
		(start 262.752332 -211.341716)
		(end 262.514334 -211.341716)
		(width 0.101854)
		(layer "F.Cu")
		(net "M_D_CPU0_SB_DQ<19>")
	)
	(segment
		(start 262.50011 -211.35594)
		(end 262.146288 -211.35594)
		(width 0.20066)
		(layer "F.Cu")
		(net "M_D_CPU0_SB_DQ<19>")
	)
	(segment
		(start 262.514334 -211.341716)
		(end 262.50011 -211.35594)
		(width 0.101854)
		(layer "F.Cu")
		(net "M_D_CPU0_SB_DQ<19>")
	)
	(segment
		(start 264.825226 -211.341716)
		(end 262.752332 -211.341716)
		(width 0.1016)
		(layer "F.Cu")
		(net "M_D_CPU0_SB_DQ<19>")
	)
	(segment
		(start 267.724382 -210.916774)
		(end 266.90828 -210.916774)
		(width 0.20066)
		(layer "F.Cu")
		(net "M_D_CPU0_SB_DQ<19>")
	)
	(segment
		(start 266.042394 -210.912456)
		(end 265.64717 -210.912456)
		(width 0.20066)
		(layer "F.Cu")
		(net "M_D_CPU0_SB_DQ<19>")
	)
	(segment
		(start 265.518646 -211.04098)
		(end 265.518646 -211.192618)
		(width 0.20066)
		(layer "F.Cu")
		(net "M_D_CPU0_SB_DQ<19>")
	)
	(segment
		(start 345.013534 -233.87812)
		(end 345.01328 -233.877866)
		(width 0.20066)
		(layer "F.Cu")
		(net "M_D_CPU0_SB_DQ<19>")
	)
	(segment
		(start 266.90828 -210.916774)
		(end 266.700762 -211.124292)
		(width 0.20066)
		(layer "F.Cu")
		(net "M_D_CPU0_SB_DQ<19>")
	)
	(segment
		(start 266.700762 -211.124292)
		(end 266.25423 -211.124292)
		(width 0.20066)
		(layer "F.Cu")
		(net "M_D_CPU0_SB_DQ<19>")
	)
	(segment
		(start 265.518646 -211.192618)
		(end 265.369548 -211.341716)
		(width 0.20066)
		(layer "F.Cu")
		(net "M_D_CPU0_SB_DQ<19>")
	)
	(segment
		(start 268.829282 -210.916774)
		(end 267.724382 -210.916774)
		(width 0.20066)
		(layer "F.Cu")
		(net "M_D_CPU0_SB_DQ<19>")
	)
	(segment
		(start 262.003794 -211.213446)
		(end 262.003794 -211.042758)
		(width 0.20066)
		(layer "F.Cu")
		(net "M_D_CPU0_SB_DQ<19>")
	)
	(segment
		(start 261.87781 -210.916774)
		(end 260.180582 -210.916774)
		(width 0.20066)
		(layer "F.Cu")
		(net "M_D_CPU0_SB_DQ<19>")
	)
	(segment
		(start 262.146288 -211.35594)
		(end 262.003794 -211.213446)
		(width 0.20066)
		(layer "F.Cu")
		(net "M_D_CPU0_SB_DQ<19>")
	)
	(segment
		(start 345.01328 -233.877866)
		(end 345.01328 -233.34218)
		(width 0.20066)
		(layer "F.Cu")
		(net "M_D_CPU0_SB_DQ<19>")
	)
	(segment
		(start 262.003794 -211.042758)
		(end 261.87781 -210.916774)
		(width 0.20066)
		(layer "F.Cu")
		(net "M_D_CPU0_SB_DQ<19>")
	)
	(segment
		(start 266.25423 -211.124292)
		(end 266.042394 -210.912456)
		(width 0.20066)
		(layer "F.Cu")
		(net "M_D_CPU0_SB_DQ<19>")
	)
	(segment
		(start 265.64717 -210.912456)
		(end 265.518646 -211.04098)
		(width 0.20066)
		(layer "F.Cu")
		(net "M_D_CPU0_SB_DQ<19>")
	)
	(segment
		(start 265.369548 -211.341716)
		(end 264.825226 -211.341716)
		(width 0.20066)
		(layer "F.Cu")
		(net "M_D_CPU0_SB_DQ<19>")
	)
	(segment
		(start 312.036968 -214.643208)
		(end 311.03951 -214.643208)
		(width 0.18288)
		(layer "In6.Cu")
		(net "M_D_CPU0_SB_DQ<19>")
	)
	(segment
		(start 281.27833 -211.341462)
		(end 280.428192 -212.1916)
		(width 0.18288)
		(layer "In6.Cu")
		(net "M_D_CPU0_SB_DQ<19>")
	)
	(segment
		(start 332.32598 -231.963214)
		(end 331.673708 -231.963214)
		(width 0.088646)
		(layer "In6.Cu")
		(net "M_D_CPU0_SB_DQ<19>")
	)
	(segment
		(start 331.673708 -231.963214)
		(end 331.467206 -231.756712)
		(width 0.088646)
		(layer "In6.Cu")
		(net "M_D_CPU0_SB_DQ<19>")
	)
	(segment
		(start 305.141884 -211.937092)
		(end 305.141884 -212.231224)
		(width 0.18288)
		(layer "In6.Cu")
		(net "M_D_CPU0_SB_DQ<19>")
	)
	(segment
		(start 275.434298 -210.391502)
		(end 275.251418 -210.208622)
		(width 0.18288)
		(layer "In6.Cu")
		(net "M_D_CPU0_SB_DQ<19>")
	)
	(segment
		(start 310.132984 -213.736682)
		(end 309.49646 -213.100158)
		(width 0.18288)
		(layer "In6.Cu")
		(net "M_D_CPU0_SB_DQ<19>")
	)
	(segment
		(start 302.994822 -211.340954)
		(end 297.941746 -211.340954)
		(width 0.18288)
		(layer "In6.Cu")
		(net "M_D_CPU0_SB_DQ<19>")
	)
	(segment
		(start 311.020714 -213.301326)
		(end 310.794654 -213.301326)
		(width 0.18288)
		(layer "In6.Cu")
		(net "M_D_CPU0_SB_DQ<19>")
	)
	(segment
		(start 280.428192 -212.1916)
		(end 279.42032 -212.1916)
		(width 0.18288)
		(layer "In6.Cu")
		(net "M_D_CPU0_SB_DQ<19>")
	)
	(segment
		(start 273.308572 -211.493862)
		(end 269.40637 -211.493862)
		(width 0.18288)
		(layer "In6.Cu")
		(net "M_D_CPU0_SB_DQ<19>")
	)
	(segment
		(start 274.743418 -210.391502)
		(end 274.743418 -211.139278)
		(width 0.18288)
		(layer "In6.Cu")
		(net "M_D_CPU0_SB_DQ<19>")
	)
	(segment
		(start 339.187536 -233.666538)
		(end 339.177122 -233.660442)
		(width 0.088646)
		(layer "In6.Cu")
		(net "M_D_CPU0_SB_DQ<19>")
	)
	(segment
		(start 277.095204 -211.581238)
		(end 276.836124 -211.322158)
		(width 0.18288)
		(layer "In6.Cu")
		(net "M_D_CPU0_SB_DQ<19>")
	)
	(segment
		(start 313.829446 -216.670382)
		(end 312.326274 -215.16721)
		(width 0.18288)
		(layer "In6.Cu")
		(net "M_D_CPU0_SB_DQ<19>")
	)
	(segment
		(start 344.65895 -233.247438)
		(end 344.25509 -233.01452)
		(width 0.088646)
		(layer "In6.Cu")
		(net "M_D_CPU0_SB_DQ<19>")
	)
	(segment
		(start 333.463392 -232.846626)
		(end 333.452978 -232.852722)
		(width 0.088646)
		(layer "In6.Cu")
		(net "M_D_CPU0_SB_DQ<19>")
	)
	(segment
		(start 312.326274 -215.16721)
		(end 312.326274 -214.932514)
		(width 0.18288)
		(layer "In6.Cu")
		(net "M_D_CPU0_SB_DQ<19>")
	)
	(segment
		(start 307.598572 -213.100158)
		(end 306.912518 -212.414104)
		(width 0.18288)
		(layer "In6.Cu")
		(net "M_D_CPU0_SB_DQ<19>")
	)
	(segment
		(start 331.467206 -231.756712)
		(end 331.467206 -230.672386)
		(width 0.088646)
		(layer "In6.Cu")
		(net "M_D_CPU0_SB_DQ<19>")
	)
	(segment
		(start 279.42032 -212.1916)
		(end 278.809958 -211.581238)
		(width 0.18288)
		(layer "In6.Cu")
		(net "M_D_CPU0_SB_DQ<19>")
	)
	(segment
		(start 274.743418 -211.139278)
		(end 274.560538 -211.322158)
		(width 0.18288)
		(layer "In6.Cu")
		(net "M_D_CPU0_SB_DQ<19>")
	)
	(segment
		(start 341.066882 -233.666538)
		(end 341.05215 -233.657902)
		(width 0.088646)
		(layer "In6.Cu")
		(net "M_D_CPU0_SB_DQ<19>")
	)
	(segment
		(start 342.389968 -233.661458)
		(end 342.381078 -233.666538)
		(width 0.088646)
		(layer "In6.Cu")
		(net "M_D_CPU0_SB_DQ<19>")
	)
	(segment
		(start 275.251418 -210.208622)
		(end 274.926298 -210.208622)
		(width 0.18288)
		(layer "In6.Cu")
		(net "M_D_CPU0_SB_DQ<19>")
	)
	(segment
		(start 338.247482 -233.666538)
		(end 338.23275 -233.657902)
		(width 0.088646)
		(layer "In6.Cu")
		(net "M_D_CPU0_SB_DQ<19>")
	)
	(segment
		(start 273.480276 -211.322158)
		(end 273.308572 -211.493862)
		(width 0.18288)
		(layer "In6.Cu")
		(net "M_D_CPU0_SB_DQ<19>")
	)
	(segment
		(start 333.452978 -232.852722)
		(end 333.445866 -232.856786)
		(width 0.088646)
		(layer "In6.Cu")
		(net "M_D_CPU0_SB_DQ<19>")
	)
	(segment
		(start 305.324764 -211.754212)
		(end 305.141884 -211.937092)
		(width 0.18288)
		(layer "In6.Cu")
		(net "M_D_CPU0_SB_DQ<19>")
	)
	(segment
		(start 337.307682 -233.666538)
		(end 337.29295 -233.657902)
		(width 0.088646)
		(layer "In6.Cu")
		(net "M_D_CPU0_SB_DQ<19>")
	)
	(segment
		(start 313.829446 -217.069924)
		(end 313.829446 -216.670382)
		(width 0.18288)
		(layer "In6.Cu")
		(net "M_D_CPU0_SB_DQ<19>")
	)
	(segment
		(start 288.792158 -211.341462)
		(end 281.27833 -211.341462)
		(width 0.18288)
		(layer "In6.Cu")
		(net "M_D_CPU0_SB_DQ<19>")
	)
	(segment
		(start 310.78297 -214.386668)
		(end 310.78297 -214.160608)
		(width 0.18288)
		(layer "In6.Cu")
		(net "M_D_CPU0_SB_DQ<19>")
	)
	(segment
		(start 310.78297 -214.160608)
		(end 311.21858 -213.725252)
		(width 0.18288)
		(layer "In6.Cu")
		(net "M_D_CPU0_SB_DQ<19>")
	)
	(segment
		(start 310.359044 -213.736682)
		(end 310.132984 -213.736682)
		(width 0.18288)
		(layer "In6.Cu")
		(net "M_D_CPU0_SB_DQ<19>")
	)
	(segment
		(start 310.794654 -213.301326)
		(end 310.359044 -213.736682)
		(width 0.18288)
		(layer "In6.Cu")
		(net "M_D_CPU0_SB_DQ<19>")
	)
	(segment
		(start 305.649884 -211.754212)
		(end 305.324764 -211.754212)
		(width 0.18288)
		(layer "In6.Cu")
		(net "M_D_CPU0_SB_DQ<19>")
	)
	(segment
		(start 312.326274 -214.932514)
		(end 312.036968 -214.643208)
		(width 0.18288)
		(layer "In6.Cu")
		(net "M_D_CPU0_SB_DQ<19>")
	)
	(segment
		(start 291.708078 -210.839304)
		(end 289.294316 -210.839304)
		(width 0.18288)
		(layer "In6.Cu")
		(net "M_D_CPU0_SB_DQ<19>")
	)
	(segment
		(start 274.560538 -211.322158)
		(end 273.480276 -211.322158)
		(width 0.18288)
		(layer "In6.Cu")
		(net "M_D_CPU0_SB_DQ<19>")
	)
	(segment
		(start 293.059612 -212.190838)
		(end 291.708078 -210.839304)
		(width 0.18288)
		(layer "In6.Cu")
		(net "M_D_CPU0_SB_DQ<19>")
	)
	(segment
		(start 276.836124 -211.322158)
		(end 275.617178 -211.322158)
		(width 0.18288)
		(layer "In6.Cu")
		(net "M_D_CPU0_SB_DQ<19>")
	)
	(segment
		(start 289.294316 -210.839304)
		(end 288.792158 -211.341462)
		(width 0.18288)
		(layer "In6.Cu")
		(net "M_D_CPU0_SB_DQ<19>")
	)
	(segment
		(start 278.809958 -211.581238)
		(end 277.095204 -211.581238)
		(width 0.18288)
		(layer "In6.Cu")
		(net "M_D_CPU0_SB_DQ<19>")
	)
	(segment
		(start 343.326974 -233.021124)
		(end 343.31529 -233.01452)
		(width 0.088646)
		(layer "In6.Cu")
		(net "M_D_CPU0_SB_DQ<19>")
	)
	(segment
		(start 335.332832 -232.852722)
		(end 335.32191 -232.859072)
		(width 0.088646)
		(layer "In6.Cu")
		(net "M_D_CPU0_SB_DQ<19>")
	)
	(segment
		(start 340.127082 -233.666538)
		(end 340.116668 -233.660442)
		(width 0.088646)
		(layer "In6.Cu")
		(net "M_D_CPU0_SB_DQ<19>")
	)
	(segment
		(start 330.57211 -229.962964)
		(end 325.070724 -229.962964)
		(width 0.18288)
		(layer "In6.Cu")
		(net "M_D_CPU0_SB_DQ<19>")
	)
	(segment
		(start 306.912518 -212.414104)
		(end 306.015644 -212.414104)
		(width 0.18288)
		(layer "In6.Cu")
		(net "M_D_CPU0_SB_DQ<19>")
	)
	(segment
		(start 274.926298 -210.208622)
		(end 274.743418 -210.391502)
		(width 0.18288)
		(layer "In6.Cu")
		(net "M_D_CPU0_SB_DQ<19>")
	)
	(segment
		(start 334.029558 -232.859072)
		(end 334.018636 -232.852722)
		(width 0.088646)
		(layer "In6.Cu")
		(net "M_D_CPU0_SB_DQ<19>")
	)
	(segment
		(start 304.067972 -212.414104)
		(end 302.994822 -211.340954)
		(width 0.18288)
		(layer "In6.Cu")
		(net "M_D_CPU0_SB_DQ<19>")
	)
	(segment
		(start 332.89113 -232.528364)
		(end 332.89113 -232.518458)
		(width 0.088646)
		(layer "In6.Cu")
		(net "M_D_CPU0_SB_DQ<19>")
	)
	(segment
		(start 297.941746 -211.340954)
		(end 297.091862 -212.190838)
		(width 0.18288)
		(layer "In6.Cu")
		(net "M_D_CPU0_SB_DQ<19>")
	)
	(segment
		(start 309.49646 -213.100158)
		(end 307.598572 -213.100158)
		(width 0.18288)
		(layer "In6.Cu")
		(net "M_D_CPU0_SB_DQ<19>")
	)
	(segment
		(start 330.757784 -229.962964)
		(end 330.57211 -229.962964)
		(width 0.088646)
		(layer "In6.Cu")
		(net "M_D_CPU0_SB_DQ<19>")
	)
	(segment
		(start 305.832764 -212.231224)
		(end 305.832764 -211.937092)
		(width 0.18288)
		(layer "In6.Cu")
		(net "M_D_CPU0_SB_DQ<19>")
	)
	(segment
		(start 336.180684 -233.350816)
		(end 336.180684 -233.332274)
		(width 0.088646)
		(layer "In6.Cu")
		(net "M_D_CPU0_SB_DQ<19>")
	)
	(segment
		(start 275.617178 -211.322158)
		(end 275.434298 -211.139278)
		(width 0.18288)
		(layer "In6.Cu")
		(net "M_D_CPU0_SB_DQ<19>")
	)
	(segment
		(start 275.434298 -211.139278)
		(end 275.434298 -210.391502)
		(width 0.18288)
		(layer "In6.Cu")
		(net "M_D_CPU0_SB_DQ<19>")
	)
	(segment
		(start 311.21858 -213.725252)
		(end 311.21858 -213.499192)
		(width 0.18288)
		(layer "In6.Cu")
		(net "M_D_CPU0_SB_DQ<19>")
	)
	(segment
		(start 321.10553 -225.99777)
		(end 321.10553 -222.986092)
		(width 0.18288)
		(layer "In6.Cu")
		(net "M_D_CPU0_SB_DQ<19>")
	)
	(segment
		(start 306.015644 -212.414104)
		(end 305.832764 -212.231224)
		(width 0.18288)
		(layer "In6.Cu")
		(net "M_D_CPU0_SB_DQ<19>")
	)
	(segment
		(start 311.03951 -214.643208)
		(end 310.78297 -214.386668)
		(width 0.18288)
		(layer "In6.Cu")
		(net "M_D_CPU0_SB_DQ<19>")
	)
	(segment
		(start 315.47689 -217.357452)
		(end 314.116974 -217.357452)
		(width 0.18288)
		(layer "In6.Cu")
		(net "M_D_CPU0_SB_DQ<19>")
	)
	(segment
		(start 342.006682 -233.666538)
		(end 341.99195 -233.657902)
		(width 0.088646)
		(layer "In6.Cu")
		(net "M_D_CPU0_SB_DQ<19>")
	)
	(segment
		(start 325.070724 -229.962964)
		(end 321.10553 -225.99777)
		(width 0.18288)
		(layer "In6.Cu")
		(net "M_D_CPU0_SB_DQ<19>")
	)
	(segment
		(start 304.959004 -212.414104)
		(end 304.067972 -212.414104)
		(width 0.18288)
		(layer "In6.Cu")
		(net "M_D_CPU0_SB_DQ<19>")
	)
	(segment
		(start 305.832764 -211.937092)
		(end 305.649884 -211.754212)
		(width 0.18288)
		(layer "In6.Cu")
		(net "M_D_CPU0_SB_DQ<19>")
	)
	(segment
		(start 297.091862 -212.190838)
		(end 293.059612 -212.190838)
		(width 0.18288)
		(layer "In6.Cu")
		(net "M_D_CPU0_SB_DQ<19>")
	)
	(segment
		(start 269.40637 -211.493862)
		(end 268.829282 -210.916774)
		(width 0.18288)
		(layer "In6.Cu")
		(net "M_D_CPU0_SB_DQ<19>")
	)
	(segment
		(start 311.21858 -213.499192)
		(end 311.020714 -213.301326)
		(width 0.18288)
		(layer "In6.Cu")
		(net "M_D_CPU0_SB_DQ<19>")
	)
	(segment
		(start 333.078836 -232.852976)
		(end 333.073248 -232.849928)
		(width 0.088646)
		(layer "In6.Cu")
		(net "M_D_CPU0_SB_DQ<19>")
	)
	(segment
		(start 331.467206 -230.672386)
		(end 330.757784 -229.962964)
		(width 0.088646)
		(layer "In6.Cu")
		(net "M_D_CPU0_SB_DQ<19>")
	)
	(segment
		(start 314.116974 -217.357452)
		(end 313.829446 -217.069924)
		(width 0.18288)
		(layer "In6.Cu")
		(net "M_D_CPU0_SB_DQ<19>")
	)
	(segment
		(start 321.10553 -222.986092)
		(end 315.47689 -217.357452)
		(width 0.18288)
		(layer "In6.Cu")
		(net "M_D_CPU0_SB_DQ<19>")
	)
	(segment
		(start 305.141884 -212.231224)
		(end 304.959004 -212.414104)
		(width 0.18288)
		(layer "In6.Cu")
		(net "M_D_CPU0_SB_DQ<19>")
	)
	(arc
		(start 341.99195 -233.657902)
		(mid 341.715509 -233.590736)
		(end 341.441278 -233.666538)
		(width 0.088646)
		(layer "In6.Cu")
		(net "M_D_CPU0_SB_DQ<19>")
	)
	(arc
		(start 334.393032 -232.852976)
		(mid 334.212088 -232.903033)
		(end 334.029558 -232.859072)
		(width 0.088646)
		(layer "In6.Cu")
		(net "M_D_CPU0_SB_DQ<19>")
	)
	(arc
		(start 336.742278 -233.666538)
		(mid 336.55508 -233.716681)
		(end 336.367882 -233.666538)
		(width 0.088646)
		(layer "In6.Cu")
		(net "M_D_CPU0_SB_DQ<19>")
	)
	(arc
		(start 338.23275 -233.657902)
		(mid 337.956309 -233.590736)
		(end 337.682078 -233.666538)
		(width 0.088646)
		(layer "In6.Cu")
		(net "M_D_CPU0_SB_DQ<19>")
	)
	(arc
		(start 341.05215 -233.657902)
		(mid 340.775709 -233.590736)
		(end 340.501478 -233.666538)
		(width 0.088646)
		(layer "In6.Cu")
		(net "M_D_CPU0_SB_DQ<19>")
	)
	(arc
		(start 344.25509 -233.01452)
		(mid 344.070235 -232.96757)
		(end 343.886282 -233.017822)
		(width 0.088646)
		(layer "In6.Cu")
		(net "M_D_CPU0_SB_DQ<19>")
	)
	(arc
		(start 338.621878 -233.666538)
		(mid 338.43468 -233.716681)
		(end 338.247482 -233.666538)
		(width 0.088646)
		(layer "In6.Cu")
		(net "M_D_CPU0_SB_DQ<19>")
	)
	(arc
		(start 339.177122 -233.660442)
		(mid 338.89869 -233.590628)
		(end 338.621878 -233.666538)
		(width 0.088646)
		(layer "In6.Cu")
		(net "M_D_CPU0_SB_DQ<19>")
	)
	(arc
		(start 337.682078 -233.666538)
		(mid 337.49488 -233.716681)
		(end 337.307682 -233.666538)
		(width 0.088646)
		(layer "In6.Cu")
		(net "M_D_CPU0_SB_DQ<19>")
	)
	(arc
		(start 334.018636 -232.852722)
		(mid 333.741823 -232.776886)
		(end 333.463392 -232.846626)
		(width 0.088646)
		(layer "In6.Cu")
		(net "M_D_CPU0_SB_DQ<19>")
	)
	(arc
		(start 336.367882 -233.666538)
		(mid 336.232949 -233.533184)
		(end 336.180684 -233.350816)
		(width 0.088646)
		(layer "In6.Cu")
		(net "M_D_CPU0_SB_DQ<19>")
	)
	(arc
		(start 343.31529 -233.01452)
		(mid 343.130435 -232.96757)
		(end 342.946482 -233.017822)
		(width 0.088646)
		(layer "In6.Cu")
		(net "M_D_CPU0_SB_DQ<19>")
	)
	(arc
		(start 335.898236 -232.852722)
		(mid 335.615534 -232.776946)
		(end 335.332832 -232.852722)
		(width 0.088646)
		(layer "In6.Cu")
		(net "M_D_CPU0_SB_DQ<19>")
	)
	(arc
		(start 342.381078 -233.666538)
		(mid 342.19388 -233.716681)
		(end 342.006682 -233.666538)
		(width 0.088646)
		(layer "In6.Cu")
		(net "M_D_CPU0_SB_DQ<19>")
	)
	(arc
		(start 341.441278 -233.666538)
		(mid 341.25408 -233.716681)
		(end 341.066882 -233.666538)
		(width 0.088646)
		(layer "In6.Cu")
		(net "M_D_CPU0_SB_DQ<19>")
	)
	(arc
		(start 345.01328 -233.34218)
		(mid 344.829892 -233.318085)
		(end 344.65895 -233.247438)
		(width 0.088646)
		(layer "In6.Cu")
		(net "M_D_CPU0_SB_DQ<19>")
	)
	(arc
		(start 340.501478 -233.666538)
		(mid 340.31428 -233.716681)
		(end 340.127082 -233.666538)
		(width 0.088646)
		(layer "In6.Cu")
		(net "M_D_CPU0_SB_DQ<19>")
	)
	(arc
		(start 343.886282 -233.017822)
		(mid 343.607079 -233.093462)
		(end 343.326974 -233.021124)
		(width 0.088646)
		(layer "In6.Cu")
		(net "M_D_CPU0_SB_DQ<19>")
	)
	(arc
		(start 333.445866 -232.856786)
		(mid 333.261858 -232.902899)
		(end 333.078836 -232.852976)
		(width 0.088646)
		(layer "In6.Cu")
		(net "M_D_CPU0_SB_DQ<19>")
	)
	(arc
		(start 332.89113 -232.518458)
		(mid 332.722145 -232.125194)
		(end 332.32598 -231.963214)
		(width 0.088646)
		(layer "In6.Cu")
		(net "M_D_CPU0_SB_DQ<19>")
	)
	(arc
		(start 335.32191 -232.859072)
		(mid 335.13938 -232.903066)
		(end 334.958436 -232.852976)
		(width 0.088646)
		(layer "In6.Cu")
		(net "M_D_CPU0_SB_DQ<19>")
	)
	(arc
		(start 337.29295 -233.657902)
		(mid 337.016509 -233.590736)
		(end 336.742278 -233.666538)
		(width 0.088646)
		(layer "In6.Cu")
		(net "M_D_CPU0_SB_DQ<19>")
	)
	(arc
		(start 340.116668 -233.660442)
		(mid 339.83849 -233.59075)
		(end 339.561932 -233.666538)
		(width 0.088646)
		(layer "In6.Cu")
		(net "M_D_CPU0_SB_DQ<19>")
	)
	(arc
		(start 336.180684 -233.332274)
		(mid 336.102573 -233.055325)
		(end 335.898236 -232.852722)
		(width 0.088646)
		(layer "In6.Cu")
		(net "M_D_CPU0_SB_DQ<19>")
	)
	(arc
		(start 339.561932 -233.666538)
		(mid 339.374734 -233.716681)
		(end 339.187536 -233.666538)
		(width 0.088646)
		(layer "In6.Cu")
		(net "M_D_CPU0_SB_DQ<19>")
	)
	(arc
		(start 333.073248 -232.849928)
		(mid 332.939805 -232.713147)
		(end 332.89113 -232.528364)
		(width 0.088646)
		(layer "In6.Cu")
		(net "M_D_CPU0_SB_DQ<19>")
	)
	(arc
		(start 342.946482 -233.017822)
		(mid 342.730175 -233.183607)
		(end 342.563958 -233.399584)
		(width 0.088646)
		(layer "In6.Cu")
		(net "M_D_CPU0_SB_DQ<19>")
	)
	(arc
		(start 342.563958 -233.399584)
		(mid 342.505802 -233.549697)
		(end 342.389968 -233.661458)
		(width 0.088646)
		(layer "In6.Cu")
		(net "M_D_CPU0_SB_DQ<19>")
	)
	(arc
		(start 334.958436 -232.852976)
		(mid 334.675734 -232.777234)
		(end 334.393032 -232.852976)
		(width 0.088646)
		(layer "In6.Cu")
		(net "M_D_CPU0_SB_DQ<19>")
	)
	(segment
		(start 265.769344 -212.828632)
		(end 265.601958 -212.661246)
		(width 0.20066)
		(layer "F.Cu")
		(net "M_D_CPU0_SB_DQ<18>")
	)
	(segment
		(start 262.51027 -212.191854)
		(end 262.50011 -212.181694)
		(width 0.101854)
		(layer "F.Cu")
		(net "M_D_CPU0_SB_DQ<18>")
	)
	(segment
		(start 266.197842 -212.828632)
		(end 265.769344 -212.828632)
		(width 0.20066)
		(layer "F.Cu")
		(net "M_D_CPU0_SB_DQ<18>")
	)
	(segment
		(start 261.762748 -212.181694)
		(end 261.327646 -212.616796)
		(width 0.20066)
		(layer "F.Cu")
		(net "M_D_CPU0_SB_DQ<18>")
	)
	(segment
		(start 268.829282 -212.616796)
		(end 267.724382 -212.616796)
		(width 0.20066)
		(layer "F.Cu")
		(net "M_D_CPU0_SB_DQ<18>")
	)
	(segment
		(start 264.825226 -212.191854)
		(end 262.765286 -212.191854)
		(width 0.1016)
		(layer "F.Cu")
		(net "M_D_CPU0_SB_DQ<18>")
	)
	(segment
		(start 261.327646 -212.616796)
		(end 260.180582 -212.616796)
		(width 0.20066)
		(layer "F.Cu")
		(net "M_D_CPU0_SB_DQ<18>")
	)
	(segment
		(start 344.54338 -234.69219)
		(end 344.543634 -234.691936)
		(width 0.20066)
		(layer "F.Cu")
		(net "M_D_CPU0_SB_DQ<18>")
	)
	(segment
		(start 266.409678 -212.616796)
		(end 266.197842 -212.828632)
		(width 0.20066)
		(layer "F.Cu")
		(net "M_D_CPU0_SB_DQ<18>")
	)
	(segment
		(start 265.601958 -212.335618)
		(end 265.458194 -212.191854)
		(width 0.20066)
		(layer "F.Cu")
		(net "M_D_CPU0_SB_DQ<18>")
	)
	(segment
		(start 265.601958 -212.661246)
		(end 265.601958 -212.335618)
		(width 0.20066)
		(layer "F.Cu")
		(net "M_D_CPU0_SB_DQ<18>")
	)
	(segment
		(start 262.765286 -212.191854)
		(end 262.51027 -212.191854)
		(width 0.101854)
		(layer "F.Cu")
		(net "M_D_CPU0_SB_DQ<18>")
	)
	(segment
		(start 262.50011 -212.181694)
		(end 261.762748 -212.181694)
		(width 0.20066)
		(layer "F.Cu")
		(net "M_D_CPU0_SB_DQ<18>")
	)
	(segment
		(start 265.458194 -212.191854)
		(end 264.825226 -212.191854)
		(width 0.20066)
		(layer "F.Cu")
		(net "M_D_CPU0_SB_DQ<18>")
	)
	(segment
		(start 344.543634 -234.691936)
		(end 344.543634 -234.15625)
		(width 0.20066)
		(layer "F.Cu")
		(net "M_D_CPU0_SB_DQ<18>")
	)
	(segment
		(start 267.724382 -212.616796)
		(end 266.409678 -212.616796)
		(width 0.20066)
		(layer "F.Cu")
		(net "M_D_CPU0_SB_DQ<18>")
	)
	(segment
		(start 292.520878 -213.892384)
		(end 291.348668 -212.720174)
		(width 0.18288)
		(layer "In6.Cu")
		(net "M_D_CPU0_SB_DQ<18>")
	)
	(segment
		(start 300.660054 -213.237318)
		(end 299.938948 -213.237318)
		(width 0.18288)
		(layer "In6.Cu")
		(net "M_D_CPU0_SB_DQ<18>")
	)
	(segment
		(start 269.426182 -213.213696)
		(end 268.829282 -212.616796)
		(width 0.18288)
		(layer "In6.Cu")
		(net "M_D_CPU0_SB_DQ<18>")
	)
	(segment
		(start 310.959754 -216.276936)
		(end 310.121554 -215.438736)
		(width 0.18288)
		(layer "In6.Cu")
		(net "M_D_CPU0_SB_DQ<18>")
	)
	(segment
		(start 330.843636 -230.958644)
		(end 330.57211 -230.958644)
		(width 0.088646)
		(layer "In6.Cu")
		(net "M_D_CPU0_SB_DQ<18>")
	)
	(segment
		(start 299.742606 -213.040976)
		(end 298.359068 -213.040976)
		(width 0.18288)
		(layer "In6.Cu")
		(net "M_D_CPU0_SB_DQ<18>")
	)
	(segment
		(start 320.099436 -226.442778)
		(end 320.099436 -223.501458)
		(width 0.18288)
		(layer "In6.Cu")
		(net "M_D_CPU0_SB_DQ<18>")
	)
	(segment
		(start 311.982104 -216.276936)
		(end 310.959754 -216.276936)
		(width 0.18288)
		(layer "In6.Cu")
		(net "M_D_CPU0_SB_DQ<18>")
	)
	(segment
		(start 324.615302 -230.958644)
		(end 320.099436 -226.442778)
		(width 0.18288)
		(layer "In6.Cu")
		(net "M_D_CPU0_SB_DQ<18>")
	)
	(segment
		(start 281.338528 -213.041484)
		(end 280.488644 -213.891368)
		(width 0.18288)
		(layer "In6.Cu")
		(net "M_D_CPU0_SB_DQ<18>")
	)
	(segment
		(start 333.933292 -233.660696)
		(end 333.922878 -233.666792)
		(width 0.088646)
		(layer "In6.Cu")
		(net "M_D_CPU0_SB_DQ<18>")
	)
	(segment
		(start 334.876648 -233.658918)
		(end 334.862932 -233.667046)
		(width 0.088646)
		(layer "In6.Cu")
		(net "M_D_CPU0_SB_DQ<18>")
	)
	(segment
		(start 270.667734 -213.030816)
		(end 270.484854 -213.213696)
		(width 0.18288)
		(layer "In6.Cu")
		(net "M_D_CPU0_SB_DQ<18>")
	)
	(segment
		(start 310.121554 -215.438736)
		(end 309.55488 -215.438736)
		(width 0.18288)
		(layer "In6.Cu")
		(net "M_D_CPU0_SB_DQ<18>")
	)
	(segment
		(start 331.065886 -231.986582)
		(end 331.065886 -231.180894)
		(width 0.088646)
		(layer "In6.Cu")
		(net "M_D_CPU0_SB_DQ<18>")
	)
	(segment
		(start 275.267166 -213.907878)
		(end 274.950682 -213.907878)
		(width 0.18288)
		(layer "In6.Cu")
		(net "M_D_CPU0_SB_DQ<18>")
	)
	(segment
		(start 312.39079 -217.336878)
		(end 312.39079 -216.685622)
		(width 0.18288)
		(layer "In6.Cu")
		(net "M_D_CPU0_SB_DQ<18>")
	)
	(segment
		(start 342.859868 -234.475528)
		(end 342.850978 -234.480608)
		(width 0.088646)
		(layer "In6.Cu")
		(net "M_D_CPU0_SB_DQ<18>")
	)
	(segment
		(start 284.453076 -213.041484)
		(end 281.338528 -213.041484)
		(width 0.18288)
		(layer "In6.Cu")
		(net "M_D_CPU0_SB_DQ<18>")
	)
	(segment
		(start 274.584922 -213.006686)
		(end 273.309588 -213.006686)
		(width 0.18288)
		(layer "In6.Cu")
		(net "M_D_CPU0_SB_DQ<18>")
	)
	(segment
		(start 271.358614 -212.718904)
		(end 271.175734 -212.536024)
		(width 0.18288)
		(layer "In6.Cu")
		(net "M_D_CPU0_SB_DQ<18>")
	)
	(segment
		(start 270.484854 -213.213696)
		(end 269.426182 -213.213696)
		(width 0.18288)
		(layer "In6.Cu")
		(net "M_D_CPU0_SB_DQ<18>")
	)
	(segment
		(start 306.772056 -213.940136)
		(end 303.790604 -213.940136)
		(width 0.18288)
		(layer "In6.Cu")
		(net "M_D_CPU0_SB_DQ<18>")
	)
	(segment
		(start 339.106764 -234.471972)
		(end 339.092032 -234.480608)
		(width 0.088646)
		(layer "In6.Cu")
		(net "M_D_CPU0_SB_DQ<18>")
	)
	(segment
		(start 335.898236 -234.480608)
		(end 335.889346 -234.475528)
		(width 0.088646)
		(layer "In6.Cu")
		(net "M_D_CPU0_SB_DQ<18>")
	)
	(segment
		(start 297.50766 -213.892384)
		(end 292.520878 -213.892384)
		(width 0.18288)
		(layer "In6.Cu")
		(net "M_D_CPU0_SB_DQ<18>")
	)
	(segment
		(start 303.087786 -213.237318)
		(end 301.716694 -213.237318)
		(width 0.18288)
		(layer "In6.Cu")
		(net "M_D_CPU0_SB_DQ<18>")
	)
	(segment
		(start 274.767802 -213.189566)
		(end 274.584922 -213.006686)
		(width 0.18288)
		(layer "In6.Cu")
		(net "M_D_CPU0_SB_DQ<18>")
	)
	(segment
		(start 270.667734 -212.718904)
		(end 270.667734 -213.030816)
		(width 0.18288)
		(layer "In6.Cu")
		(net "M_D_CPU0_SB_DQ<18>")
	)
	(segment
		(start 330.57211 -230.958644)
		(end 324.615302 -230.958644)
		(width 0.18288)
		(layer "In6.Cu")
		(net "M_D_CPU0_SB_DQ<18>")
	)
	(segment
		(start 275.458682 -213.716362)
		(end 275.267166 -213.907878)
		(width 0.18288)
		(layer "In6.Cu")
		(net "M_D_CPU0_SB_DQ<18>")
	)
	(segment
		(start 332.992476 -233.661712)
		(end 332.983586 -233.667046)
		(width 0.088646)
		(layer "In6.Cu")
		(net "M_D_CPU0_SB_DQ<18>")
	)
	(segment
		(start 314.983368 -218.38539)
		(end 313.439302 -218.38539)
		(width 0.18288)
		(layer "In6.Cu")
		(net "M_D_CPU0_SB_DQ<18>")
	)
	(segment
		(start 335.710784 -234.15625)
		(end 335.71053 -234.137708)
		(width 0.088646)
		(layer "In6.Cu")
		(net "M_D_CPU0_SB_DQ<18>")
	)
	(segment
		(start 271.541494 -213.213696)
		(end 271.358614 -213.030816)
		(width 0.18288)
		(layer "In6.Cu")
		(net "M_D_CPU0_SB_DQ<18>")
	)
	(segment
		(start 332.60919 -233.666792)
		(end 332.594966 -233.658664)
		(width 0.088646)
		(layer "In6.Cu")
		(net "M_D_CPU0_SB_DQ<18>")
	)
	(segment
		(start 334.499458 -233.673142)
		(end 334.488536 -233.666792)
		(width 0.088646)
		(layer "In6.Cu")
		(net "M_D_CPU0_SB_DQ<18>")
	)
	(segment
		(start 291.348668 -212.720174)
		(end 290.640516 -212.720174)
		(width 0.18288)
		(layer "In6.Cu")
		(net "M_D_CPU0_SB_DQ<18>")
	)
	(segment
		(start 301.716694 -213.237318)
		(end 301.533814 -213.054438)
		(width 0.18288)
		(layer "In6.Cu")
		(net "M_D_CPU0_SB_DQ<18>")
	)
	(segment
		(start 320.099436 -223.501458)
		(end 314.983368 -218.38539)
		(width 0.18288)
		(layer "In6.Cu")
		(net "M_D_CPU0_SB_DQ<18>")
	)
	(segment
		(start 301.533814 -212.601556)
		(end 301.350934 -212.418676)
		(width 0.18288)
		(layer "In6.Cu")
		(net "M_D_CPU0_SB_DQ<18>")
	)
	(segment
		(start 300.842934 -212.601556)
		(end 300.842934 -213.054438)
		(width 0.18288)
		(layer "In6.Cu")
		(net "M_D_CPU0_SB_DQ<18>")
	)
	(segment
		(start 301.025814 -212.418676)
		(end 300.842934 -212.601556)
		(width 0.18288)
		(layer "In6.Cu")
		(net "M_D_CPU0_SB_DQ<18>")
	)
	(segment
		(start 275.458682 -213.189566)
		(end 275.458682 -213.716362)
		(width 0.18288)
		(layer "In6.Cu")
		(net "M_D_CPU0_SB_DQ<18>")
	)
	(segment
		(start 313.439302 -218.38539)
		(end 312.39079 -217.336878)
		(width 0.18288)
		(layer "In6.Cu")
		(net "M_D_CPU0_SB_DQ<18>")
	)
	(segment
		(start 340.986364 -234.471972)
		(end 340.971632 -234.480608)
		(width 0.088646)
		(layer "In6.Cu")
		(net "M_D_CPU0_SB_DQ<18>")
	)
	(segment
		(start 280.488644 -213.891368)
		(end 279.42032 -213.891368)
		(width 0.18288)
		(layer "In6.Cu")
		(net "M_D_CPU0_SB_DQ<18>")
	)
	(segment
		(start 290.457636 -213.203028)
		(end 290.270438 -213.390226)
		(width 0.18288)
		(layer "In6.Cu")
		(net "M_D_CPU0_SB_DQ<18>")
	)
	(segment
		(start 273.102578 -213.213696)
		(end 271.541494 -213.213696)
		(width 0.18288)
		(layer "In6.Cu")
		(net "M_D_CPU0_SB_DQ<18>")
	)
	(segment
		(start 341.921846 -234.474512)
		(end 341.911432 -234.480608)
		(width 0.088646)
		(layer "In6.Cu")
		(net "M_D_CPU0_SB_DQ<18>")
	)
	(segment
		(start 301.533814 -213.054438)
		(end 301.533814 -212.601556)
		(width 0.18288)
		(layer "In6.Cu")
		(net "M_D_CPU0_SB_DQ<18>")
	)
	(segment
		(start 290.640516 -212.720174)
		(end 290.457636 -212.903054)
		(width 0.18288)
		(layer "In6.Cu")
		(net "M_D_CPU0_SB_DQ<18>")
	)
	(segment
		(start 287.511236 -213.263226)
		(end 284.674818 -213.263226)
		(width 0.18288)
		(layer "In6.Cu")
		(net "M_D_CPU0_SB_DQ<18>")
	)
	(segment
		(start 331.065886 -231.180894)
		(end 330.843636 -230.958644)
		(width 0.088646)
		(layer "In6.Cu")
		(net "M_D_CPU0_SB_DQ<18>")
	)
	(segment
		(start 277.095966 -213.006686)
		(end 275.641562 -213.006686)
		(width 0.18288)
		(layer "In6.Cu")
		(net "M_D_CPU0_SB_DQ<18>")
	)
	(segment
		(start 273.309588 -213.006686)
		(end 273.102578 -213.213696)
		(width 0.18288)
		(layer "In6.Cu")
		(net "M_D_CPU0_SB_DQ<18>")
	)
	(segment
		(start 299.938948 -213.237318)
		(end 299.742606 -213.040976)
		(width 0.18288)
		(layer "In6.Cu")
		(net "M_D_CPU0_SB_DQ<18>")
	)
	(segment
		(start 277.370032 -213.280752)
		(end 277.095966 -213.006686)
		(width 0.18288)
		(layer "In6.Cu")
		(net "M_D_CPU0_SB_DQ<18>")
	)
	(segment
		(start 289.766756 -213.207346)
		(end 289.766756 -212.903054)
		(width 0.18288)
		(layer "In6.Cu")
		(net "M_D_CPU0_SB_DQ<18>")
	)
	(segment
		(start 279.42032 -213.891368)
		(end 278.809704 -213.280752)
		(width 0.18288)
		(layer "In6.Cu")
		(net "M_D_CPU0_SB_DQ<18>")
	)
	(segment
		(start 270.850614 -212.536024)
		(end 270.667734 -212.718904)
		(width 0.18288)
		(layer "In6.Cu")
		(net "M_D_CPU0_SB_DQ<18>")
	)
	(segment
		(start 332.620112 -233.673142)
		(end 332.60919 -233.666792)
		(width 0.088646)
		(layer "In6.Cu")
		(net "M_D_CPU0_SB_DQ<18>")
	)
	(segment
		(start 308.94655 -214.830406)
		(end 307.662326 -214.830406)
		(width 0.18288)
		(layer "In6.Cu")
		(net "M_D_CPU0_SB_DQ<18>")
	)
	(segment
		(start 331.856334 -232.77703)
		(end 331.065886 -231.986582)
		(width 0.088646)
		(layer "In6.Cu")
		(net "M_D_CPU0_SB_DQ<18>")
	)
	(segment
		(start 289.949636 -213.390226)
		(end 289.766756 -213.207346)
		(width 0.18288)
		(layer "In6.Cu")
		(net "M_D_CPU0_SB_DQ<18>")
	)
	(segment
		(start 278.809704 -213.280752)
		(end 277.370032 -213.280752)
		(width 0.18288)
		(layer "In6.Cu")
		(net "M_D_CPU0_SB_DQ<18>")
	)
	(segment
		(start 300.842934 -213.054438)
		(end 300.660054 -213.237318)
		(width 0.18288)
		(layer "In6.Cu")
		(net "M_D_CPU0_SB_DQ<18>")
	)
	(segment
		(start 274.950682 -213.907878)
		(end 274.767802 -213.724998)
		(width 0.18288)
		(layer "In6.Cu")
		(net "M_D_CPU0_SB_DQ<18>")
	)
	(segment
		(start 290.270438 -213.390226)
		(end 289.949636 -213.390226)
		(width 0.18288)
		(layer "In6.Cu")
		(net "M_D_CPU0_SB_DQ<18>")
	)
	(segment
		(start 340.046564 -234.471972)
		(end 340.031832 -234.480608)
		(width 0.088646)
		(layer "In6.Cu")
		(net "M_D_CPU0_SB_DQ<18>")
	)
	(segment
		(start 275.641562 -213.006686)
		(end 275.458682 -213.189566)
		(width 0.18288)
		(layer "In6.Cu")
		(net "M_D_CPU0_SB_DQ<18>")
	)
	(segment
		(start 312.39079 -216.685622)
		(end 311.982104 -216.276936)
		(width 0.18288)
		(layer "In6.Cu")
		(net "M_D_CPU0_SB_DQ<18>")
	)
	(segment
		(start 284.674818 -213.263226)
		(end 284.453076 -213.041484)
		(width 0.18288)
		(layer "In6.Cu")
		(net "M_D_CPU0_SB_DQ<18>")
	)
	(segment
		(start 301.350934 -212.418676)
		(end 301.025814 -212.418676)
		(width 0.18288)
		(layer "In6.Cu")
		(net "M_D_CPU0_SB_DQ<18>")
	)
	(segment
		(start 337.227164 -234.471972)
		(end 337.212432 -234.480608)
		(width 0.088646)
		(layer "In6.Cu")
		(net "M_D_CPU0_SB_DQ<18>")
	)
	(segment
		(start 336.287364 -234.471972)
		(end 336.272632 -234.480608)
		(width 0.088646)
		(layer "In6.Cu")
		(net "M_D_CPU0_SB_DQ<18>")
	)
	(segment
		(start 309.55488 -215.438736)
		(end 308.94655 -214.830406)
		(width 0.18288)
		(layer "In6.Cu")
		(net "M_D_CPU0_SB_DQ<18>")
	)
	(segment
		(start 274.767802 -213.724998)
		(end 274.767802 -213.189566)
		(width 0.18288)
		(layer "In6.Cu")
		(net "M_D_CPU0_SB_DQ<18>")
	)
	(segment
		(start 271.175734 -212.536024)
		(end 270.850614 -212.536024)
		(width 0.18288)
		(layer "In6.Cu")
		(net "M_D_CPU0_SB_DQ<18>")
	)
	(segment
		(start 289.766756 -212.903054)
		(end 289.583876 -212.720174)
		(width 0.18288)
		(layer "In6.Cu")
		(net "M_D_CPU0_SB_DQ<18>")
	)
	(segment
		(start 333.557118 -233.671618)
		(end 333.548736 -233.666792)
		(width 0.088646)
		(layer "In6.Cu")
		(net "M_D_CPU0_SB_DQ<18>")
	)
	(segment
		(start 288.054288 -212.720174)
		(end 287.511236 -213.263226)
		(width 0.18288)
		(layer "In6.Cu")
		(net "M_D_CPU0_SB_DQ<18>")
	)
	(segment
		(start 289.583876 -212.720174)
		(end 288.054288 -212.720174)
		(width 0.18288)
		(layer "In6.Cu")
		(net "M_D_CPU0_SB_DQ<18>")
	)
	(segment
		(start 290.457636 -212.903054)
		(end 290.457636 -213.203028)
		(width 0.18288)
		(layer "In6.Cu")
		(net "M_D_CPU0_SB_DQ<18>")
	)
	(segment
		(start 303.790604 -213.940136)
		(end 303.087786 -213.237318)
		(width 0.18288)
		(layer "In6.Cu")
		(net "M_D_CPU0_SB_DQ<18>")
	)
	(segment
		(start 298.359068 -213.040976)
		(end 297.50766 -213.892384)
		(width 0.18288)
		(layer "In6.Cu")
		(net "M_D_CPU0_SB_DQ<18>")
	)
	(segment
		(start 307.662326 -214.830406)
		(end 306.772056 -213.940136)
		(width 0.18288)
		(layer "In6.Cu")
		(net "M_D_CPU0_SB_DQ<18>")
	)
	(segment
		(start 271.358614 -213.030816)
		(end 271.358614 -212.718904)
		(width 0.18288)
		(layer "In6.Cu")
		(net "M_D_CPU0_SB_DQ<18>")
	)
	(arc
		(start 336.272632 -234.480608)
		(mid 336.085434 -234.530751)
		(end 335.898236 -234.480608)
		(width 0.088646)
		(layer "In6.Cu")
		(net "M_D_CPU0_SB_DQ<18>")
	)
	(arc
		(start 333.548736 -233.666792)
		(mid 333.271264 -233.591074)
		(end 332.992476 -233.661712)
		(width 0.088646)
		(layer "In6.Cu")
		(net "M_D_CPU0_SB_DQ<18>")
	)
	(arc
		(start 340.031832 -234.480608)
		(mid 339.844634 -234.530751)
		(end 339.657436 -234.480608)
		(width 0.088646)
		(layer "In6.Cu")
		(net "M_D_CPU0_SB_DQ<18>")
	)
	(arc
		(start 344.543634 -234.15625)
		(mid 344.137912 -233.938037)
		(end 343.702894 -233.786426)
		(width 0.088646)
		(layer "In6.Cu")
		(net "M_D_CPU0_SB_DQ<18>")
	)
	(arc
		(start 337.777836 -234.480608)
		(mid 337.503637 -234.404773)
		(end 337.227164 -234.471972)
		(width 0.088646)
		(layer "In6.Cu")
		(net "M_D_CPU0_SB_DQ<18>")
	)
	(arc
		(start 342.850978 -234.480608)
		(mid 342.66378 -234.530751)
		(end 342.476582 -234.480608)
		(width 0.088646)
		(layer "In6.Cu")
		(net "M_D_CPU0_SB_DQ<18>")
	)
	(arc
		(start 332.421738 -233.342688)
		(mid 332.256225 -232.942723)
		(end 331.856334 -232.77703)
		(width 0.088646)
		(layer "In6.Cu")
		(net "M_D_CPU0_SB_DQ<18>")
	)
	(arc
		(start 336.838036 -234.480608)
		(mid 336.563837 -234.404773)
		(end 336.287364 -234.471972)
		(width 0.088646)
		(layer "In6.Cu")
		(net "M_D_CPU0_SB_DQ<18>")
	)
	(arc
		(start 338.152232 -234.480608)
		(mid 337.965034 -234.530751)
		(end 337.777836 -234.480608)
		(width 0.088646)
		(layer "In6.Cu")
		(net "M_D_CPU0_SB_DQ<18>")
	)
	(arc
		(start 341.537036 -234.480608)
		(mid 341.262837 -234.404773)
		(end 340.986364 -234.471972)
		(width 0.088646)
		(layer "In6.Cu")
		(net "M_D_CPU0_SB_DQ<18>")
	)
	(arc
		(start 337.212432 -234.480608)
		(mid 337.025234 -234.530751)
		(end 336.838036 -234.480608)
		(width 0.088646)
		(layer "In6.Cu")
		(net "M_D_CPU0_SB_DQ<18>")
	)
	(arc
		(start 335.428336 -233.666792)
		(mid 335.153509 -233.590981)
		(end 334.876648 -233.658918)
		(width 0.088646)
		(layer "In6.Cu")
		(net "M_D_CPU0_SB_DQ<18>")
	)
	(arc
		(start 339.657436 -234.480608)
		(mid 339.383237 -234.404773)
		(end 339.106764 -234.471972)
		(width 0.088646)
		(layer "In6.Cu")
		(net "M_D_CPU0_SB_DQ<18>")
	)
	(arc
		(start 343.702894 -233.786426)
		(mid 343.522992 -233.769731)
		(end 343.347294 -233.811826)
		(width 0.088646)
		(layer "In6.Cu")
		(net "M_D_CPU0_SB_DQ<18>")
	)
	(arc
		(start 338.717636 -234.480608)
		(mid 338.434934 -234.404832)
		(end 338.152232 -234.480608)
		(width 0.088646)
		(layer "In6.Cu")
		(net "M_D_CPU0_SB_DQ<18>")
	)
	(arc
		(start 335.889346 -234.475528)
		(mid 335.758432 -234.339168)
		(end 335.710784 -234.15625)
		(width 0.088646)
		(layer "In6.Cu")
		(net "M_D_CPU0_SB_DQ<18>")
	)
	(arc
		(start 332.983586 -233.667046)
		(mid 332.802642 -233.717137)
		(end 332.620112 -233.673142)
		(width 0.088646)
		(layer "In6.Cu")
		(net "M_D_CPU0_SB_DQ<18>")
	)
	(arc
		(start 340.971632 -234.480608)
		(mid 340.784434 -234.530751)
		(end 340.597236 -234.480608)
		(width 0.088646)
		(layer "In6.Cu")
		(net "M_D_CPU0_SB_DQ<18>")
	)
	(arc
		(start 333.922878 -233.666792)
		(mid 333.740627 -233.716903)
		(end 333.557118 -233.671618)
		(width 0.088646)
		(layer "In6.Cu")
		(net "M_D_CPU0_SB_DQ<18>")
	)
	(arc
		(start 339.092032 -234.480608)
		(mid 338.904834 -234.530751)
		(end 338.717636 -234.480608)
		(width 0.088646)
		(layer "In6.Cu")
		(net "M_D_CPU0_SB_DQ<18>")
	)
	(arc
		(start 335.71053 -234.137708)
		(mid 335.630457 -233.865667)
		(end 335.428336 -233.666792)
		(width 0.088646)
		(layer "In6.Cu")
		(net "M_D_CPU0_SB_DQ<18>")
	)
	(arc
		(start 341.911432 -234.480608)
		(mid 341.724234 -234.530751)
		(end 341.537036 -234.480608)
		(width 0.088646)
		(layer "In6.Cu")
		(net "M_D_CPU0_SB_DQ<18>")
	)
	(arc
		(start 332.594966 -233.658664)
		(mid 332.467923 -233.522848)
		(end 332.421738 -233.342688)
		(width 0.088646)
		(layer "In6.Cu")
		(net "M_D_CPU0_SB_DQ<18>")
	)
	(arc
		(start 340.597236 -234.480608)
		(mid 340.323037 -234.404773)
		(end 340.046564 -234.471972)
		(width 0.088646)
		(layer "In6.Cu")
		(net "M_D_CPU0_SB_DQ<18>")
	)
	(arc
		(start 342.476582 -234.480608)
		(mid 342.200023 -234.404865)
		(end 341.921846 -234.474512)
		(width 0.088646)
		(layer "In6.Cu")
		(net "M_D_CPU0_SB_DQ<18>")
	)
	(arc
		(start 334.488536 -233.666792)
		(mid 334.211723 -233.590922)
		(end 333.933292 -233.660696)
		(width 0.088646)
		(layer "In6.Cu")
		(net "M_D_CPU0_SB_DQ<18>")
	)
	(arc
		(start 334.862932 -233.667046)
		(mid 334.681988 -233.717137)
		(end 334.499458 -233.673142)
		(width 0.088646)
		(layer "In6.Cu")
		(net "M_D_CPU0_SB_DQ<18>")
	)
	(arc
		(start 343.347294 -233.811826)
		(mid 343.138226 -233.971921)
		(end 343.033858 -234.213654)
		(width 0.088646)
		(layer "In6.Cu")
		(net "M_D_CPU0_SB_DQ<18>")
	)
	(arc
		(start 343.033858 -234.213654)
		(mid 342.975702 -234.363767)
		(end 342.859868 -234.475528)
		(width 0.088646)
		(layer "In6.Cu")
		(net "M_D_CPU0_SB_DQ<18>")
	)
	(segment
		(start 261.560056 -211.341716)
		(end 261.381494 -211.341716)
		(width 0.20066)
		(layer "F.Cu")
		(net "M_D_CPU0_SB_DQ<17>")
	)
	(segment
		(start 258.130548 -211.977986)
		(end 257.626104 -211.977986)
		(width 0.20066)
		(layer "F.Cu")
		(net "M_D_CPU0_SB_DQ<17>")
	)
	(segment
		(start 343.133934 -233.87812)
		(end 343.13368 -233.877866)
		(width 0.20066)
		(layer "F.Cu")
		(net "M_D_CPU0_SB_DQ<17>")
	)
	(segment
		(start 264.729214 -211.766658)
		(end 263.624314 -211.766658)
		(width 0.20066)
		(layer "F.Cu")
		(net "M_D_CPU0_SB_DQ<17>")
	)
	(segment
		(start 257.626104 -211.977986)
		(end 257.414776 -211.766658)
		(width 0.20066)
		(layer "F.Cu")
		(net "M_D_CPU0_SB_DQ<17>")
	)
	(segment
		(start 257.414776 -211.766658)
		(end 256.080514 -211.766658)
		(width 0.20066)
		(layer "F.Cu")
		(net "M_D_CPU0_SB_DQ<17>")
	)
	(segment
		(start 261.050786 -211.341716)
		(end 259.065268 -211.341716)
		(width 0.1016)
		(layer "F.Cu")
		(net "M_D_CPU0_SB_DQ<17>")
	)
	(segment
		(start 343.13368 -233.877866)
		(end 343.13368 -233.34218)
		(width 0.20066)
		(layer "F.Cu")
		(net "M_D_CPU0_SB_DQ<17>")
	)
	(segment
		(start 258.28498 -211.495386)
		(end 258.28498 -211.823554)
		(width 0.20066)
		(layer "F.Cu")
		(net "M_D_CPU0_SB_DQ<17>")
	)
	(segment
		(start 258.44754 -211.332826)
		(end 258.28498 -211.495386)
		(width 0.20066)
		(layer "F.Cu")
		(net "M_D_CPU0_SB_DQ<17>")
	)
	(segment
		(start 263.624314 -211.766658)
		(end 261.984998 -211.766658)
		(width 0.20066)
		(layer "F.Cu")
		(net "M_D_CPU0_SB_DQ<17>")
	)
	(segment
		(start 259.065268 -211.341716)
		(end 259.056378 -211.332826)
		(width 0.1016)
		(layer "F.Cu")
		(net "M_D_CPU0_SB_DQ<17>")
	)
	(segment
		(start 261.381494 -211.341716)
		(end 261.050786 -211.341716)
		(width 0.101854)
		(layer "F.Cu")
		(net "M_D_CPU0_SB_DQ<17>")
	)
	(segment
		(start 258.28498 -211.823554)
		(end 258.130548 -211.977986)
		(width 0.20066)
		(layer "F.Cu")
		(net "M_D_CPU0_SB_DQ<17>")
	)
	(segment
		(start 259.056378 -211.332826)
		(end 258.44754 -211.332826)
		(width 0.20066)
		(layer "F.Cu")
		(net "M_D_CPU0_SB_DQ<17>")
	)
	(segment
		(start 261.984998 -211.766658)
		(end 261.560056 -211.341716)
		(width 0.20066)
		(layer "F.Cu")
		(net "M_D_CPU0_SB_DQ<17>")
	)
	(segment
		(start 266.0269 -212.682836)
		(end 266.0269 -212.373718)
		(width 0.18288)
		(layer "In6.Cu")
		(net "M_D_CPU0_SB_DQ<17>")
	)
	(segment
		(start 308.80558 -213.781386)
		(end 307.52415 -213.781386)
		(width 0.18288)
		(layer "In6.Cu")
		(net "M_D_CPU0_SB_DQ<17>")
	)
	(segment
		(start 341.921846 -233.837988)
		(end 341.911432 -233.831892)
		(width 0.088646)
		(layer "In6.Cu")
		(net "M_D_CPU0_SB_DQ<17>")
	)
	(segment
		(start 266.71778 -212.373718)
		(end 266.71778 -212.682836)
		(width 0.18288)
		(layer "In6.Cu")
		(net "M_D_CPU0_SB_DQ<17>")
	)
	(segment
		(start 266.90066 -212.190838)
		(end 266.71778 -212.373718)
		(width 0.18288)
		(layer "In6.Cu")
		(net "M_D_CPU0_SB_DQ<17>")
	)
	(segment
		(start 278.530812 -212.151976)
		(end 277.154894 -212.151976)
		(width 0.18288)
		(layer "In6.Cu")
		(net "M_D_CPU0_SB_DQ<17>")
	)
	(segment
		(start 265.15314 -212.190838)
		(end 264.729214 -211.766658)
		(width 0.18288)
		(layer "In6.Cu")
		(net "M_D_CPU0_SB_DQ<17>")
	)
	(segment
		(start 332.70063 -232.542588)
		(end 332.70063 -232.528364)
		(width 0.088646)
		(layer "In6.Cu")
		(net "M_D_CPU0_SB_DQ<17>")
	)
	(segment
		(start 337.227164 -233.840528)
		(end 337.212432 -233.831892)
		(width 0.088646)
		(layer "In6.Cu")
		(net "M_D_CPU0_SB_DQ<17>")
	)
	(segment
		(start 266.71778 -212.682836)
		(end 266.5349 -212.865716)
		(width 0.18288)
		(layer "In6.Cu")
		(net "M_D_CPU0_SB_DQ<17>")
	)
	(segment
		(start 273.328892 -212.371686)
		(end 272.980912 -212.023706)
		(width 0.18288)
		(layer "In6.Cu")
		(net "M_D_CPU0_SB_DQ<17>")
	)
	(segment
		(start 335.98993 -233.356404)
		(end 335.98993 -233.333544)
		(width 0.088646)
		(layer "In6.Cu")
		(net "M_D_CPU0_SB_DQ<17>")
	)
	(segment
		(start 302.75022 -211.909152)
		(end 300.10735 -211.909152)
		(width 0.18288)
		(layer "In6.Cu")
		(net "M_D_CPU0_SB_DQ<17>")
	)
	(segment
		(start 272.980912 -212.023706)
		(end 269.267432 -212.023706)
		(width 0.18288)
		(layer "In6.Cu")
		(net "M_D_CPU0_SB_DQ<17>")
	)
	(segment
		(start 330.57211 -230.460804)
		(end 324.864476 -230.460804)
		(width 0.18288)
		(layer "In6.Cu")
		(net "M_D_CPU0_SB_DQ<17>")
	)
	(segment
		(start 320.60769 -226.204018)
		(end 320.60769 -223.19234)
		(width 0.18288)
		(layer "In6.Cu")
		(net "M_D_CPU0_SB_DQ<17>")
	)
	(segment
		(start 315.277246 -217.861896)
		(end 313.840876 -217.861896)
		(width 0.18288)
		(layer "In6.Cu")
		(net "M_D_CPU0_SB_DQ<17>")
	)
	(segment
		(start 332.32598 -232.15346)
		(end 331.594714 -232.15346)
		(width 0.088646)
		(layer "In6.Cu")
		(net "M_D_CPU0_SB_DQ<17>")
	)
	(segment
		(start 290.505388 -211.498434)
		(end 290.180268 -211.498434)
		(width 0.18288)
		(layer "In6.Cu")
		(net "M_D_CPU0_SB_DQ<17>")
	)
	(segment
		(start 303.824894 -212.983826)
		(end 302.75022 -211.909152)
		(width 0.18288)
		(layer "In6.Cu")
		(net "M_D_CPU0_SB_DQ<17>")
	)
	(segment
		(start 291.628322 -212.1916)
		(end 290.871148 -212.1916)
		(width 0.18288)
		(layer "In6.Cu")
		(net "M_D_CPU0_SB_DQ<17>")
	)
	(segment
		(start 274.568412 -212.371686)
		(end 273.328892 -212.371686)
		(width 0.18288)
		(layer "In6.Cu")
		(net "M_D_CPU0_SB_DQ<17>")
	)
	(segment
		(start 324.864476 -230.460804)
		(end 320.60769 -226.204018)
		(width 0.18288)
		(layer "In6.Cu")
		(net "M_D_CPU0_SB_DQ<17>")
	)
	(segment
		(start 266.5349 -212.865716)
		(end 266.20978 -212.865716)
		(width 0.18288)
		(layer "In6.Cu")
		(net "M_D_CPU0_SB_DQ<17>")
	)
	(segment
		(start 313.239404 -217.260424)
		(end 313.239404 -216.805256)
		(width 0.18288)
		(layer "In6.Cu")
		(net "M_D_CPU0_SB_DQ<17>")
	)
	(segment
		(start 330.853796 -230.460804)
		(end 330.57211 -230.460804)
		(width 0.088646)
		(layer "In6.Cu")
		(net "M_D_CPU0_SB_DQ<17>")
	)
	(segment
		(start 281.338528 -212.1916)
		(end 280.488644 -213.041484)
		(width 0.18288)
		(layer "In6.Cu")
		(net "M_D_CPU0_SB_DQ<17>")
	)
	(segment
		(start 300.10735 -211.909152)
		(end 299.825664 -212.190838)
		(width 0.18288)
		(layer "In6.Cu")
		(net "M_D_CPU0_SB_DQ<17>")
	)
	(segment
		(start 289.814508 -212.1916)
		(end 281.338528 -212.1916)
		(width 0.18288)
		(layer "In6.Cu")
		(net "M_D_CPU0_SB_DQ<17>")
	)
	(segment
		(start 275.442172 -212.188806)
		(end 275.442172 -212.066378)
		(width 0.18288)
		(layer "In6.Cu")
		(net "M_D_CPU0_SB_DQ<17>")
	)
	(segment
		(start 340.046564 -233.840528)
		(end 340.031832 -233.831892)
		(width 0.088646)
		(layer "In6.Cu")
		(net "M_D_CPU0_SB_DQ<17>")
	)
	(segment
		(start 310.341772 -214.893906)
		(end 309.9181 -214.893906)
		(width 0.18288)
		(layer "In6.Cu")
		(net "M_D_CPU0_SB_DQ<17>")
	)
	(segment
		(start 266.20978 -212.865716)
		(end 266.0269 -212.682836)
		(width 0.18288)
		(layer "In6.Cu")
		(net "M_D_CPU0_SB_DQ<17>")
	)
	(segment
		(start 274.751292 -212.188806)
		(end 274.568412 -212.371686)
		(width 0.18288)
		(layer "In6.Cu")
		(net "M_D_CPU0_SB_DQ<17>")
	)
	(segment
		(start 266.0269 -212.373718)
		(end 265.84402 -212.190838)
		(width 0.18288)
		(layer "In6.Cu")
		(net "M_D_CPU0_SB_DQ<17>")
	)
	(segment
		(start 331.27696 -231.835706)
		(end 331.27696 -230.883968)
		(width 0.088646)
		(layer "In6.Cu")
		(net "M_D_CPU0_SB_DQ<17>")
	)
	(segment
		(start 276.935184 -212.371686)
		(end 275.625052 -212.371686)
		(width 0.18288)
		(layer "In6.Cu")
		(net "M_D_CPU0_SB_DQ<17>")
	)
	(segment
		(start 277.154894 -212.151976)
		(end 276.935184 -212.371686)
		(width 0.18288)
		(layer "In6.Cu")
		(net "M_D_CPU0_SB_DQ<17>")
	)
	(segment
		(start 275.442172 -212.066378)
		(end 275.259292 -211.883498)
		(width 0.18288)
		(layer "In6.Cu")
		(net "M_D_CPU0_SB_DQ<17>")
	)
	(segment
		(start 335.428336 -233.017822)
		(end 335.41462 -233.02595)
		(width 0.088646)
		(layer "In6.Cu")
		(net "M_D_CPU0_SB_DQ<17>")
	)
	(segment
		(start 274.751292 -212.066378)
		(end 274.751292 -212.188806)
		(width 0.18288)
		(layer "In6.Cu")
		(net "M_D_CPU0_SB_DQ<17>")
	)
	(segment
		(start 313.239404 -216.805256)
		(end 312.16727 -215.733122)
		(width 0.18288)
		(layer "In6.Cu")
		(net "M_D_CPU0_SB_DQ<17>")
	)
	(segment
		(start 289.997388 -211.681314)
		(end 289.997388 -212.00872)
		(width 0.18288)
		(layer "In6.Cu")
		(net "M_D_CPU0_SB_DQ<17>")
	)
	(segment
		(start 280.488644 -213.041484)
		(end 279.42032 -213.041484)
		(width 0.18288)
		(layer "In6.Cu")
		(net "M_D_CPU0_SB_DQ<17>")
	)
	(segment
		(start 311.180988 -215.733122)
		(end 310.341772 -214.893906)
		(width 0.18288)
		(layer "In6.Cu")
		(net "M_D_CPU0_SB_DQ<17>")
	)
	(segment
		(start 290.180268 -211.498434)
		(end 289.997388 -211.681314)
		(width 0.18288)
		(layer "In6.Cu")
		(net "M_D_CPU0_SB_DQ<17>")
	)
	(segment
		(start 340.986364 -233.840528)
		(end 340.971632 -233.831892)
		(width 0.088646)
		(layer "In6.Cu")
		(net "M_D_CPU0_SB_DQ<17>")
	)
	(segment
		(start 269.267432 -212.023706)
		(end 269.1003 -212.190838)
		(width 0.18288)
		(layer "In6.Cu")
		(net "M_D_CPU0_SB_DQ<17>")
	)
	(segment
		(start 338.166964 -233.840528)
		(end 338.152232 -233.831892)
		(width 0.088646)
		(layer "In6.Cu")
		(net "M_D_CPU0_SB_DQ<17>")
	)
	(segment
		(start 298.151296 -212.190838)
		(end 297.299888 -213.042246)
		(width 0.18288)
		(layer "In6.Cu")
		(net "M_D_CPU0_SB_DQ<17>")
	)
	(segment
		(start 290.688268 -212.00872)
		(end 290.688268 -211.681314)
		(width 0.18288)
		(layer "In6.Cu")
		(net "M_D_CPU0_SB_DQ<17>")
	)
	(segment
		(start 290.871148 -212.1916)
		(end 290.688268 -212.00872)
		(width 0.18288)
		(layer "In6.Cu")
		(net "M_D_CPU0_SB_DQ<17>")
	)
	(segment
		(start 334.488536 -233.018076)
		(end 334.478122 -233.024172)
		(width 0.088646)
		(layer "In6.Cu")
		(net "M_D_CPU0_SB_DQ<17>")
	)
	(segment
		(start 269.1003 -212.190838)
		(end 266.90066 -212.190838)
		(width 0.18288)
		(layer "In6.Cu")
		(net "M_D_CPU0_SB_DQ<17>")
	)
	(segment
		(start 292.478968 -213.042246)
		(end 291.628322 -212.1916)
		(width 0.18288)
		(layer "In6.Cu")
		(net "M_D_CPU0_SB_DQ<17>")
	)
	(segment
		(start 290.688268 -211.681314)
		(end 290.505388 -211.498434)
		(width 0.18288)
		(layer "In6.Cu")
		(net "M_D_CPU0_SB_DQ<17>")
	)
	(segment
		(start 299.825664 -212.190838)
		(end 298.151296 -212.190838)
		(width 0.18288)
		(layer "In6.Cu")
		(net "M_D_CPU0_SB_DQ<17>")
	)
	(segment
		(start 312.16727 -215.733122)
		(end 311.180988 -215.733122)
		(width 0.18288)
		(layer "In6.Cu")
		(net "M_D_CPU0_SB_DQ<17>")
	)
	(segment
		(start 275.625052 -212.371686)
		(end 275.442172 -212.188806)
		(width 0.18288)
		(layer "In6.Cu")
		(net "M_D_CPU0_SB_DQ<17>")
	)
	(segment
		(start 313.840876 -217.861896)
		(end 313.239404 -217.260424)
		(width 0.18288)
		(layer "In6.Cu")
		(net "M_D_CPU0_SB_DQ<17>")
	)
	(segment
		(start 297.299888 -213.042246)
		(end 292.478968 -213.042246)
		(width 0.18288)
		(layer "In6.Cu")
		(net "M_D_CPU0_SB_DQ<17>")
	)
	(segment
		(start 320.60769 -223.19234)
		(end 315.277246 -217.861896)
		(width 0.18288)
		(layer "In6.Cu")
		(net "M_D_CPU0_SB_DQ<17>")
	)
	(segment
		(start 331.27696 -230.883968)
		(end 330.853796 -230.460804)
		(width 0.088646)
		(layer "In6.Cu")
		(net "M_D_CPU0_SB_DQ<17>")
	)
	(segment
		(start 274.934172 -211.883498)
		(end 274.751292 -212.066378)
		(width 0.18288)
		(layer "In6.Cu")
		(net "M_D_CPU0_SB_DQ<17>")
	)
	(segment
		(start 275.259292 -211.883498)
		(end 274.934172 -211.883498)
		(width 0.18288)
		(layer "In6.Cu")
		(net "M_D_CPU0_SB_DQ<17>")
	)
	(segment
		(start 306.72659 -212.983826)
		(end 303.824894 -212.983826)
		(width 0.18288)
		(layer "In6.Cu")
		(net "M_D_CPU0_SB_DQ<17>")
	)
	(segment
		(start 289.997388 -212.00872)
		(end 289.814508 -212.1916)
		(width 0.18288)
		(layer "In6.Cu")
		(net "M_D_CPU0_SB_DQ<17>")
	)
	(segment
		(start 309.9181 -214.893906)
		(end 308.80558 -213.781386)
		(width 0.18288)
		(layer "In6.Cu")
		(net "M_D_CPU0_SB_DQ<17>")
	)
	(segment
		(start 279.42032 -213.041484)
		(end 278.530812 -212.151976)
		(width 0.18288)
		(layer "In6.Cu")
		(net "M_D_CPU0_SB_DQ<17>")
	)
	(segment
		(start 307.52415 -213.781386)
		(end 306.72659 -212.983826)
		(width 0.18288)
		(layer "In6.Cu")
		(net "M_D_CPU0_SB_DQ<17>")
	)
	(segment
		(start 265.84402 -212.190838)
		(end 265.15314 -212.190838)
		(width 0.18288)
		(layer "In6.Cu")
		(net "M_D_CPU0_SB_DQ<17>")
	)
	(segment
		(start 331.594714 -232.15346)
		(end 331.27696 -231.835706)
		(width 0.088646)
		(layer "In6.Cu")
		(net "M_D_CPU0_SB_DQ<17>")
	)
	(arc
		(start 335.41462 -233.02595)
		(mid 335.13776 -233.093822)
		(end 334.862932 -233.018076)
		(width 0.088646)
		(layer "In6.Cu")
		(net "M_D_CPU0_SB_DQ<17>")
	)
	(arc
		(start 336.838036 -233.831892)
		(mid 336.278775 -233.835387)
		(end 335.98993 -233.356404)
		(width 0.088646)
		(layer "In6.Cu")
		(net "M_D_CPU0_SB_DQ<17>")
	)
	(arc
		(start 337.777836 -233.831892)
		(mid 337.503607 -233.907817)
		(end 337.227164 -233.840528)
		(width 0.088646)
		(layer "In6.Cu")
		(net "M_D_CPU0_SB_DQ<17>")
	)
	(arc
		(start 334.478122 -233.024172)
		(mid 334.19969 -233.093986)
		(end 333.922878 -233.018076)
		(width 0.088646)
		(layer "In6.Cu")
		(net "M_D_CPU0_SB_DQ<17>")
	)
	(arc
		(start 340.971632 -233.831892)
		(mid 340.784434 -233.781749)
		(end 340.597236 -233.831892)
		(width 0.088646)
		(layer "In6.Cu")
		(net "M_D_CPU0_SB_DQ<17>")
	)
	(arc
		(start 339.092032 -233.831892)
		(mid 338.904834 -233.781749)
		(end 338.717636 -233.831892)
		(width 0.088646)
		(layer "In6.Cu")
		(net "M_D_CPU0_SB_DQ<17>")
	)
	(arc
		(start 333.548482 -233.018076)
		(mid 332.989224 -233.021573)
		(end 332.70063 -232.542588)
		(width 0.088646)
		(layer "In6.Cu")
		(net "M_D_CPU0_SB_DQ<17>")
	)
	(arc
		(start 337.212432 -233.831892)
		(mid 337.025234 -233.781749)
		(end 336.838036 -233.831892)
		(width 0.088646)
		(layer "In6.Cu")
		(net "M_D_CPU0_SB_DQ<17>")
	)
	(arc
		(start 332.70063 -232.528364)
		(mid 332.590913 -232.263357)
		(end 332.32598 -232.15346)
		(width 0.088646)
		(layer "In6.Cu")
		(net "M_D_CPU0_SB_DQ<17>")
	)
	(arc
		(start 333.922878 -233.018076)
		(mid 333.73568 -232.967933)
		(end 333.548482 -233.018076)
		(width 0.088646)
		(layer "In6.Cu")
		(net "M_D_CPU0_SB_DQ<17>")
	)
	(arc
		(start 338.717636 -233.831892)
		(mid 338.443407 -233.907817)
		(end 338.166964 -233.840528)
		(width 0.088646)
		(layer "In6.Cu")
		(net "M_D_CPU0_SB_DQ<17>")
	)
	(arc
		(start 340.597236 -233.831892)
		(mid 340.323007 -233.907817)
		(end 340.046564 -233.840528)
		(width 0.088646)
		(layer "In6.Cu")
		(net "M_D_CPU0_SB_DQ<17>")
	)
	(arc
		(start 340.031832 -233.831892)
		(mid 339.844634 -233.781749)
		(end 339.657436 -233.831892)
		(width 0.088646)
		(layer "In6.Cu")
		(net "M_D_CPU0_SB_DQ<17>")
	)
	(arc
		(start 341.911432 -233.831892)
		(mid 341.724234 -233.781749)
		(end 341.537036 -233.831892)
		(width 0.088646)
		(layer "In6.Cu")
		(net "M_D_CPU0_SB_DQ<17>")
	)
	(arc
		(start 339.657436 -233.831892)
		(mid 339.374734 -233.907634)
		(end 339.092032 -233.831892)
		(width 0.088646)
		(layer "In6.Cu")
		(net "M_D_CPU0_SB_DQ<17>")
	)
	(arc
		(start 341.537036 -233.831892)
		(mid 341.262807 -233.907817)
		(end 340.986364 -233.840528)
		(width 0.088646)
		(layer "In6.Cu")
		(net "M_D_CPU0_SB_DQ<17>")
	)
	(arc
		(start 334.862932 -233.018076)
		(mid 334.675734 -232.967967)
		(end 334.488536 -233.018076)
		(width 0.088646)
		(layer "In6.Cu")
		(net "M_D_CPU0_SB_DQ<17>")
	)
	(arc
		(start 342.476582 -233.831892)
		(mid 342.200023 -233.907601)
		(end 341.921846 -233.837988)
		(width 0.088646)
		(layer "In6.Cu")
		(net "M_D_CPU0_SB_DQ<17>")
	)
	(arc
		(start 343.13368 -233.34218)
		(mid 342.81946 -233.606262)
		(end 342.476582 -233.831892)
		(width 0.088646)
		(layer "In6.Cu")
		(net "M_D_CPU0_SB_DQ<17>")
	)
	(arc
		(start 335.98993 -233.333544)
		(mid 335.799056 -233.015735)
		(end 335.428336 -233.017822)
		(width 0.088646)
		(layer "In6.Cu")
		(net "M_D_CPU0_SB_DQ<17>")
	)
	(arc
		(start 338.152232 -233.831892)
		(mid 337.965034 -233.781749)
		(end 337.777836 -233.831892)
		(width 0.088646)
		(layer "In6.Cu")
		(net "M_D_CPU0_SB_DQ<17>")
	)
	(segment
		(start 261.381494 -213.041738)
		(end 259.31241 -213.041738)
		(width 0.1016)
		(layer "F.Cu")
		(net "M_D_CPU0_SB_DQ<16>")
	)
	(segment
		(start 259.056378 -213.03361)
		(end 258.49453 -213.03361)
		(width 0.20066)
		(layer "F.Cu")
		(net "M_D_CPU0_SB_DQ<16>")
	)
	(segment
		(start 264.729214 -213.46668)
		(end 263.624314 -213.46668)
		(width 0.20066)
		(layer "F.Cu")
		(net "M_D_CPU0_SB_DQ<16>")
	)
	(segment
		(start 258.49453 -213.03361)
		(end 258.28498 -213.24316)
		(width 0.20066)
		(layer "F.Cu")
		(net "M_D_CPU0_SB_DQ<16>")
	)
	(segment
		(start 259.31241 -213.041738)
		(end 259.064506 -213.041738)
		(width 0.101854)
		(layer "F.Cu")
		(net "M_D_CPU0_SB_DQ<16>")
	)
	(segment
		(start 258.11226 -213.70544)
		(end 257.653536 -213.70544)
		(width 0.20066)
		(layer "F.Cu")
		(net "M_D_CPU0_SB_DQ<16>")
	)
	(segment
		(start 258.28498 -213.24316)
		(end 258.28498 -213.53272)
		(width 0.20066)
		(layer "F.Cu")
		(net "M_D_CPU0_SB_DQ<16>")
	)
	(segment
		(start 257.414776 -213.46668)
		(end 256.080514 -213.46668)
		(width 0.20066)
		(layer "F.Cu")
		(net "M_D_CPU0_SB_DQ<16>")
	)
	(segment
		(start 343.60358 -234.69219)
		(end 343.603834 -234.691936)
		(width 0.20066)
		(layer "F.Cu")
		(net "M_D_CPU0_SB_DQ<16>")
	)
	(segment
		(start 343.603834 -234.691936)
		(end 343.603834 -234.15625)
		(width 0.20066)
		(layer "F.Cu")
		(net "M_D_CPU0_SB_DQ<16>")
	)
	(segment
		(start 263.624314 -213.46668)
		(end 262.255254 -213.46668)
		(width 0.20066)
		(layer "F.Cu")
		(net "M_D_CPU0_SB_DQ<16>")
	)
	(segment
		(start 259.064506 -213.041738)
		(end 259.056378 -213.03361)
		(width 0.101854)
		(layer "F.Cu")
		(net "M_D_CPU0_SB_DQ<16>")
	)
	(segment
		(start 262.255254 -213.46668)
		(end 261.830312 -213.041738)
		(width 0.20066)
		(layer "F.Cu")
		(net "M_D_CPU0_SB_DQ<16>")
	)
	(segment
		(start 261.830312 -213.041738)
		(end 261.381494 -213.041738)
		(width 0.20066)
		(layer "F.Cu")
		(net "M_D_CPU0_SB_DQ<16>")
	)
	(segment
		(start 258.28498 -213.53272)
		(end 258.11226 -213.70544)
		(width 0.20066)
		(layer "F.Cu")
		(net "M_D_CPU0_SB_DQ<16>")
	)
	(segment
		(start 257.653536 -213.70544)
		(end 257.414776 -213.46668)
		(width 0.20066)
		(layer "F.Cu")
		(net "M_D_CPU0_SB_DQ<16>")
	)
	(segment
		(start 300.842934 -213.923372)
		(end 300.660054 -213.740492)
		(width 0.18288)
		(layer "In6.Cu")
		(net "M_D_CPU0_SB_DQ<16>")
	)
	(segment
		(start 277.273004 -213.816692)
		(end 276.643592 -214.446104)
		(width 0.18288)
		(layer "In6.Cu")
		(net "M_D_CPU0_SB_DQ<16>")
	)
	(segment
		(start 293.271956 -214.541608)
		(end 293.071296 -214.742268)
		(width 0.18288)
		(layer "In6.Cu")
		(net "M_D_CPU0_SB_DQ<16>")
	)
	(segment
		(start 313.265566 -218.951556)
		(end 311.660286 -217.346276)
		(width 0.18288)
		(layer "In6.Cu")
		(net "M_D_CPU0_SB_DQ<16>")
	)
	(segment
		(start 266.210034 -214.593678)
		(end 266.027154 -214.410798)
		(width 0.18288)
		(layer "In6.Cu")
		(net "M_D_CPU0_SB_DQ<16>")
	)
	(segment
		(start 303.509426 -214.541354)
		(end 302.708564 -213.740492)
		(width 0.18288)
		(layer "In6.Cu")
		(net "M_D_CPU0_SB_DQ<16>")
	)
	(segment
		(start 279.42032 -214.741506)
		(end 278.495506 -213.816692)
		(width 0.18288)
		(layer "In6.Cu")
		(net "M_D_CPU0_SB_DQ<16>")
	)
	(segment
		(start 330.572364 -231.456484)
		(end 324.409054 -231.456484)
		(width 0.18288)
		(layer "In6.Cu")
		(net "M_D_CPU0_SB_DQ<16>")
	)
	(segment
		(start 278.495506 -213.816692)
		(end 277.273004 -213.816692)
		(width 0.18288)
		(layer "In6.Cu")
		(net "M_D_CPU0_SB_DQ<16>")
	)
	(segment
		(start 314.708794 -218.951556)
		(end 313.265566 -218.951556)
		(width 0.18288)
		(layer "In6.Cu")
		(net "M_D_CPU0_SB_DQ<16>")
	)
	(segment
		(start 273.616674 -214.446104)
		(end 272.888456 -213.717886)
		(width 0.18288)
		(layer "In6.Cu")
		(net "M_D_CPU0_SB_DQ<16>")
	)
	(segment
		(start 330.865226 -232.055162)
		(end 330.865226 -231.54513)
		(width 0.088646)
		(layer "In6.Cu")
		(net "M_D_CPU0_SB_DQ<16>")
	)
	(segment
		(start 267.226034 -213.89086)
		(end 266.900914 -213.89086)
		(width 0.18288)
		(layer "In6.Cu")
		(net "M_D_CPU0_SB_DQ<16>")
	)
	(segment
		(start 299.888148 -213.740492)
		(end 299.73778 -213.89086)
		(width 0.18288)
		(layer "In6.Cu")
		(net "M_D_CPU0_SB_DQ<16>")
	)
	(segment
		(start 331.77734 -232.967276)
		(end 330.865226 -232.055162)
		(width 0.088646)
		(layer "In6.Cu")
		(net "M_D_CPU0_SB_DQ<16>")
	)
	(segment
		(start 306.663598 -214.541354)
		(end 303.509426 -214.541354)
		(width 0.18288)
		(layer "In6.Cu")
		(net "M_D_CPU0_SB_DQ<16>")
	)
	(segment
		(start 267.916914 -214.593678)
		(end 267.591794 -214.593678)
		(width 0.18288)
		(layer "In6.Cu")
		(net "M_D_CPU0_SB_DQ<16>")
	)
	(segment
		(start 301.533814 -213.923372)
		(end 301.533814 -214.462868)
		(width 0.18288)
		(layer "In6.Cu")
		(net "M_D_CPU0_SB_DQ<16>")
	)
	(segment
		(start 268.099794 -214.07374)
		(end 268.099794 -214.410798)
		(width 0.18288)
		(layer "In6.Cu")
		(net "M_D_CPU0_SB_DQ<16>")
	)
	(segment
		(start 330.77658 -231.456484)
		(end 330.572364 -231.456484)
		(width 0.088646)
		(layer "In6.Cu")
		(net "M_D_CPU0_SB_DQ<16>")
	)
	(segment
		(start 334.969358 -233.825796)
		(end 334.958436 -233.832146)
		(width 0.088646)
		(layer "In6.Cu")
		(net "M_D_CPU0_SB_DQ<16>")
	)
	(segment
		(start 337.307682 -234.645708)
		(end 337.29295 -234.654344)
		(width 0.088646)
		(layer "In6.Cu")
		(net "M_D_CPU0_SB_DQ<16>")
	)
	(segment
		(start 266.027154 -214.410798)
		(end 266.027154 -214.07374)
		(width 0.18288)
		(layer "In6.Cu")
		(net "M_D_CPU0_SB_DQ<16>")
	)
	(segment
		(start 342.006682 -234.645708)
		(end 341.99195 -234.654344)
		(width 0.088646)
		(layer "In6.Cu")
		(net "M_D_CPU0_SB_DQ<16>")
	)
	(segment
		(start 335.520284 -234.156504)
		(end 335.520284 -234.149392)
		(width 0.088646)
		(layer "In6.Cu")
		(net "M_D_CPU0_SB_DQ<16>")
	)
	(segment
		(start 311.239154 -217.346276)
		(end 310.80329 -216.910412)
		(width 0.18288)
		(layer "In6.Cu")
		(net "M_D_CPU0_SB_DQ<16>")
	)
	(segment
		(start 334.392778 -233.832146)
		(end 334.381856 -233.825796)
		(width 0.088646)
		(layer "In6.Cu")
		(net "M_D_CPU0_SB_DQ<16>")
	)
	(segment
		(start 301.533814 -214.462868)
		(end 301.350934 -214.645748)
		(width 0.18288)
		(layer "In6.Cu")
		(net "M_D_CPU0_SB_DQ<16>")
	)
	(segment
		(start 339.187282 -234.645708)
		(end 339.176868 -234.651804)
		(width 0.088646)
		(layer "In6.Cu")
		(net "M_D_CPU0_SB_DQ<16>")
	)
	(segment
		(start 266.535154 -214.593678)
		(end 266.210034 -214.593678)
		(width 0.18288)
		(layer "In6.Cu")
		(net "M_D_CPU0_SB_DQ<16>")
	)
	(segment
		(start 332.513432 -233.832146)
		(end 332.507336 -233.82859)
		(width 0.088646)
		(layer "In6.Cu")
		(net "M_D_CPU0_SB_DQ<16>")
	)
	(segment
		(start 300.660054 -213.740492)
		(end 299.888148 -213.740492)
		(width 0.18288)
		(layer "In6.Cu")
		(net "M_D_CPU0_SB_DQ<16>")
	)
	(segment
		(start 272.888456 -213.717886)
		(end 269.57274 -213.717886)
		(width 0.18288)
		(layer "In6.Cu")
		(net "M_D_CPU0_SB_DQ<16>")
	)
	(segment
		(start 266.900914 -213.89086)
		(end 266.718034 -214.07374)
		(width 0.18288)
		(layer "In6.Cu")
		(net "M_D_CPU0_SB_DQ<16>")
	)
	(segment
		(start 268.099794 -214.410798)
		(end 267.916914 -214.593678)
		(width 0.18288)
		(layer "In6.Cu")
		(net "M_D_CPU0_SB_DQ<16>")
	)
	(segment
		(start 293.071296 -214.742268)
		(end 292.494462 -214.742268)
		(width 0.18288)
		(layer "In6.Cu")
		(net "M_D_CPU0_SB_DQ<16>")
	)
	(segment
		(start 330.865226 -231.54513)
		(end 330.77658 -231.456484)
		(width 0.088646)
		(layer "In6.Cu")
		(net "M_D_CPU0_SB_DQ<16>")
	)
	(segment
		(start 334.018382 -233.831892)
		(end 334.009492 -233.837226)
		(width 0.088646)
		(layer "In6.Cu")
		(net "M_D_CPU0_SB_DQ<16>")
	)
	(segment
		(start 301.716694 -213.740492)
		(end 301.533814 -213.923372)
		(width 0.18288)
		(layer "In6.Cu")
		(net "M_D_CPU0_SB_DQ<16>")
	)
	(segment
		(start 266.718034 -214.410798)
		(end 266.535154 -214.593678)
		(width 0.18288)
		(layer "In6.Cu")
		(net "M_D_CPU0_SB_DQ<16>")
	)
	(segment
		(start 319.510664 -226.558094)
		(end 319.510664 -223.753426)
		(width 0.18288)
		(layer "In6.Cu")
		(net "M_D_CPU0_SB_DQ<16>")
	)
	(segment
		(start 267.591794 -214.593678)
		(end 267.408914 -214.410798)
		(width 0.18288)
		(layer "In6.Cu")
		(net "M_D_CPU0_SB_DQ<16>")
	)
	(segment
		(start 334.958436 -233.832146)
		(end 334.948022 -233.838242)
		(width 0.088646)
		(layer "In6.Cu")
		(net "M_D_CPU0_SB_DQ<16>")
	)
	(segment
		(start 301.025814 -214.645748)
		(end 300.842934 -214.462868)
		(width 0.18288)
		(layer "In6.Cu")
		(net "M_D_CPU0_SB_DQ<16>")
	)
	(segment
		(start 310.80329 -216.910412)
		(end 310.155082 -216.910412)
		(width 0.18288)
		(layer "In6.Cu")
		(net "M_D_CPU0_SB_DQ<16>")
	)
	(segment
		(start 266.718034 -214.07374)
		(end 266.718034 -214.410798)
		(width 0.18288)
		(layer "In6.Cu")
		(net "M_D_CPU0_SB_DQ<16>")
	)
	(segment
		(start 300.842934 -214.462868)
		(end 300.842934 -213.923372)
		(width 0.18288)
		(layer "In6.Cu")
		(net "M_D_CPU0_SB_DQ<16>")
	)
	(segment
		(start 280.010616 -214.741506)
		(end 279.42032 -214.741506)
		(width 0.18288)
		(layer "In6.Cu")
		(net "M_D_CPU0_SB_DQ<16>")
	)
	(segment
		(start 299.73778 -213.89086)
		(end 298.462954 -213.89086)
		(width 0.18288)
		(layer "In6.Cu")
		(net "M_D_CPU0_SB_DQ<16>")
	)
	(segment
		(start 268.282674 -213.89086)
		(end 268.099794 -214.07374)
		(width 0.18288)
		(layer "In6.Cu")
		(net "M_D_CPU0_SB_DQ<16>")
	)
	(segment
		(start 294.53205 -214.541608)
		(end 293.271956 -214.541608)
		(width 0.18288)
		(layer "In6.Cu")
		(net "M_D_CPU0_SB_DQ<16>")
	)
	(segment
		(start 308.652164 -215.407494)
		(end 307.529738 -215.407494)
		(width 0.18288)
		(layer "In6.Cu")
		(net "M_D_CPU0_SB_DQ<16>")
	)
	(segment
		(start 265.153394 -213.89086)
		(end 264.729214 -213.46668)
		(width 0.18288)
		(layer "In6.Cu")
		(net "M_D_CPU0_SB_DQ<16>")
	)
	(segment
		(start 311.660286 -217.346276)
		(end 311.239154 -217.346276)
		(width 0.18288)
		(layer "In6.Cu")
		(net "M_D_CPU0_SB_DQ<16>")
	)
	(segment
		(start 294.73271 -214.742268)
		(end 294.53205 -214.541608)
		(width 0.18288)
		(layer "In6.Cu")
		(net "M_D_CPU0_SB_DQ<16>")
	)
	(segment
		(start 324.409054 -231.456484)
		(end 319.510664 -226.558094)
		(width 0.18288)
		(layer "In6.Cu")
		(net "M_D_CPU0_SB_DQ<16>")
	)
	(segment
		(start 276.643592 -214.446104)
		(end 273.616674 -214.446104)
		(width 0.18288)
		(layer "In6.Cu")
		(net "M_D_CPU0_SB_DQ<16>")
	)
	(segment
		(start 280.359866 -214.392256)
		(end 280.010616 -214.741506)
		(width 0.18288)
		(layer "In6.Cu")
		(net "M_D_CPU0_SB_DQ<16>")
	)
	(segment
		(start 297.827954 -214.52586)
		(end 295.295066 -214.52586)
		(width 0.18288)
		(layer "In6.Cu")
		(net "M_D_CPU0_SB_DQ<16>")
	)
	(segment
		(start 338.247736 -234.645708)
		(end 338.237322 -234.651804)
		(width 0.088646)
		(layer "In6.Cu")
		(net "M_D_CPU0_SB_DQ<16>")
	)
	(segment
		(start 280.837894 -214.392256)
		(end 280.359866 -214.392256)
		(width 0.18288)
		(layer "In6.Cu")
		(net "M_D_CPU0_SB_DQ<16>")
	)
	(segment
		(start 269.399766 -213.89086)
		(end 268.282674 -213.89086)
		(width 0.18288)
		(layer "In6.Cu")
		(net "M_D_CPU0_SB_DQ<16>")
	)
	(segment
		(start 291.643562 -213.891368)
		(end 281.338782 -213.891368)
		(width 0.18288)
		(layer "In6.Cu")
		(net "M_D_CPU0_SB_DQ<16>")
	)
	(segment
		(start 307.529738 -215.407494)
		(end 306.663598 -214.541354)
		(width 0.18288)
		(layer "In6.Cu")
		(net "M_D_CPU0_SB_DQ<16>")
	)
	(segment
		(start 342.958674 -234.638596)
		(end 342.946482 -234.645708)
		(width 0.088646)
		(layer "In6.Cu")
		(net "M_D_CPU0_SB_DQ<16>")
	)
	(segment
		(start 332.052422 -233.023156)
		(end 332.043532 -233.018076)
		(width 0.088646)
		(layer "In6.Cu")
		(net "M_D_CPU0_SB_DQ<16>")
	)
	(segment
		(start 331.856334 -232.967276)
		(end 331.77734 -232.967276)
		(width 0.088646)
		(layer "In6.Cu")
		(net "M_D_CPU0_SB_DQ<16>")
	)
	(segment
		(start 265.844274 -213.89086)
		(end 265.153394 -213.89086)
		(width 0.18288)
		(layer "In6.Cu")
		(net "M_D_CPU0_SB_DQ<16>")
	)
	(segment
		(start 301.350934 -214.645748)
		(end 301.025814 -214.645748)
		(width 0.18288)
		(layer "In6.Cu")
		(net "M_D_CPU0_SB_DQ<16>")
	)
	(segment
		(start 319.510664 -223.753426)
		(end 314.708794 -218.951556)
		(width 0.18288)
		(layer "In6.Cu")
		(net "M_D_CPU0_SB_DQ<16>")
	)
	(segment
		(start 333.453232 -233.832146)
		(end 333.44485 -233.82732)
		(width 0.088646)
		(layer "In6.Cu")
		(net "M_D_CPU0_SB_DQ<16>")
	)
	(segment
		(start 310.155082 -216.910412)
		(end 308.652164 -215.407494)
		(width 0.18288)
		(layer "In6.Cu")
		(net "M_D_CPU0_SB_DQ<16>")
	)
	(segment
		(start 340.127082 -234.645708)
		(end 340.11235 -234.654344)
		(width 0.088646)
		(layer "In6.Cu")
		(net "M_D_CPU0_SB_DQ<16>")
	)
	(segment
		(start 302.708564 -213.740492)
		(end 301.716694 -213.740492)
		(width 0.18288)
		(layer "In6.Cu")
		(net "M_D_CPU0_SB_DQ<16>")
	)
	(segment
		(start 341.066882 -234.645708)
		(end 341.05215 -234.654344)
		(width 0.088646)
		(layer "In6.Cu")
		(net "M_D_CPU0_SB_DQ<16>")
	)
	(segment
		(start 269.57274 -213.717886)
		(end 269.399766 -213.89086)
		(width 0.18288)
		(layer "In6.Cu")
		(net "M_D_CPU0_SB_DQ<16>")
	)
	(segment
		(start 281.338782 -213.891368)
		(end 280.837894 -214.392256)
		(width 0.18288)
		(layer "In6.Cu")
		(net "M_D_CPU0_SB_DQ<16>")
	)
	(segment
		(start 336.367882 -234.645708)
		(end 336.35061 -234.655614)
		(width 0.088646)
		(layer "In6.Cu")
		(net "M_D_CPU0_SB_DQ<16>")
	)
	(segment
		(start 335.520538 -234.175046)
		(end 335.520284 -234.156504)
		(width 0.088646)
		(layer "In6.Cu")
		(net "M_D_CPU0_SB_DQ<16>")
	)
	(segment
		(start 298.462954 -213.89086)
		(end 297.827954 -214.52586)
		(width 0.18288)
		(layer "In6.Cu")
		(net "M_D_CPU0_SB_DQ<16>")
	)
	(segment
		(start 267.408914 -214.07374)
		(end 267.226034 -213.89086)
		(width 0.18288)
		(layer "In6.Cu")
		(net "M_D_CPU0_SB_DQ<16>")
	)
	(segment
		(start 266.027154 -214.07374)
		(end 265.844274 -213.89086)
		(width 0.18288)
		(layer "In6.Cu")
		(net "M_D_CPU0_SB_DQ<16>")
	)
	(segment
		(start 333.07909 -233.832146)
		(end 333.068676 -233.838242)
		(width 0.088646)
		(layer "In6.Cu")
		(net "M_D_CPU0_SB_DQ<16>")
	)
	(segment
		(start 295.295066 -214.52586)
		(end 295.078658 -214.742268)
		(width 0.18288)
		(layer "In6.Cu")
		(net "M_D_CPU0_SB_DQ<16>")
	)
	(segment
		(start 295.078658 -214.742268)
		(end 294.73271 -214.742268)
		(width 0.18288)
		(layer "In6.Cu")
		(net "M_D_CPU0_SB_DQ<16>")
	)
	(segment
		(start 267.408914 -214.410798)
		(end 267.408914 -214.07374)
		(width 0.18288)
		(layer "In6.Cu")
		(net "M_D_CPU0_SB_DQ<16>")
	)
	(segment
		(start 292.494462 -214.742268)
		(end 291.643562 -213.891368)
		(width 0.18288)
		(layer "In6.Cu")
		(net "M_D_CPU0_SB_DQ<16>")
	)
	(arc
		(start 334.009492 -233.837226)
		(mid 333.730704 -233.907789)
		(end 333.453232 -233.832146)
		(width 0.088646)
		(layer "In6.Cu")
		(net "M_D_CPU0_SB_DQ<16>")
	)
	(arc
		(start 339.561678 -234.645708)
		(mid 339.37448 -234.595565)
		(end 339.187282 -234.645708)
		(width 0.088646)
		(layer "In6.Cu")
		(net "M_D_CPU0_SB_DQ<16>")
	)
	(arc
		(start 340.501478 -234.645708)
		(mid 340.31428 -234.595565)
		(end 340.127082 -234.645708)
		(width 0.088646)
		(layer "In6.Cu")
		(net "M_D_CPU0_SB_DQ<16>")
	)
	(arc
		(start 335.802732 -234.645962)
		(mid 335.60069 -234.447039)
		(end 335.520538 -234.175046)
		(width 0.088646)
		(layer "In6.Cu")
		(net "M_D_CPU0_SB_DQ<16>")
	)
	(arc
		(start 334.948022 -233.838242)
		(mid 334.66959 -233.908088)
		(end 334.392778 -233.832146)
		(width 0.088646)
		(layer "In6.Cu")
		(net "M_D_CPU0_SB_DQ<16>")
	)
	(arc
		(start 338.237322 -234.651804)
		(mid 337.95889 -234.72165)
		(end 337.682078 -234.645708)
		(width 0.088646)
		(layer "In6.Cu")
		(net "M_D_CPU0_SB_DQ<16>")
	)
	(arc
		(start 339.176868 -234.651804)
		(mid 338.89869 -234.721527)
		(end 338.622132 -234.645708)
		(width 0.088646)
		(layer "In6.Cu")
		(net "M_D_CPU0_SB_DQ<16>")
	)
	(arc
		(start 341.99195 -234.654344)
		(mid 341.715475 -234.721664)
		(end 341.441278 -234.645708)
		(width 0.088646)
		(layer "In6.Cu")
		(net "M_D_CPU0_SB_DQ<16>")
	)
	(arc
		(start 336.35061 -234.655614)
		(mid 336.07543 -234.721566)
		(end 335.802732 -234.645962)
		(width 0.088646)
		(layer "In6.Cu")
		(net "M_D_CPU0_SB_DQ<16>")
	)
	(arc
		(start 338.622132 -234.645708)
		(mid 338.434934 -234.595565)
		(end 338.247736 -234.645708)
		(width 0.088646)
		(layer "In6.Cu")
		(net "M_D_CPU0_SB_DQ<16>")
	)
	(arc
		(start 332.043532 -233.018076)
		(mid 331.953276 -232.980354)
		(end 331.856334 -232.967276)
		(width 0.088646)
		(layer "In6.Cu")
		(net "M_D_CPU0_SB_DQ<16>")
	)
	(arc
		(start 341.441278 -234.645708)
		(mid 341.25408 -234.595565)
		(end 341.066882 -234.645708)
		(width 0.088646)
		(layer "In6.Cu")
		(net "M_D_CPU0_SB_DQ<16>")
	)
	(arc
		(start 335.332832 -233.831892)
		(mid 335.151888 -233.781835)
		(end 334.969358 -233.825796)
		(width 0.088646)
		(layer "In6.Cu")
		(net "M_D_CPU0_SB_DQ<16>")
	)
	(arc
		(start 341.05215 -234.654344)
		(mid 340.775675 -234.721664)
		(end 340.501478 -234.645708)
		(width 0.088646)
		(layer "In6.Cu")
		(net "M_D_CPU0_SB_DQ<16>")
	)
	(arc
		(start 334.381856 -233.825796)
		(mid 334.199326 -233.781772)
		(end 334.018382 -233.831892)
		(width 0.088646)
		(layer "In6.Cu")
		(net "M_D_CPU0_SB_DQ<16>")
	)
	(arc
		(start 336.742278 -234.645708)
		(mid 336.55508 -234.595565)
		(end 336.367882 -234.645708)
		(width 0.088646)
		(layer "In6.Cu")
		(net "M_D_CPU0_SB_DQ<16>")
	)
	(arc
		(start 342.381078 -234.645708)
		(mid 342.19388 -234.595565)
		(end 342.006682 -234.645708)
		(width 0.088646)
		(layer "In6.Cu")
		(net "M_D_CPU0_SB_DQ<16>")
	)
	(arc
		(start 333.44485 -233.82732)
		(mid 333.261342 -233.782042)
		(end 333.07909 -233.832146)
		(width 0.088646)
		(layer "In6.Cu")
		(net "M_D_CPU0_SB_DQ<16>")
	)
	(arc
		(start 340.11235 -234.654344)
		(mid 339.835875 -234.721664)
		(end 339.561678 -234.645708)
		(width 0.088646)
		(layer "In6.Cu")
		(net "M_D_CPU0_SB_DQ<16>")
	)
	(arc
		(start 342.946482 -234.645708)
		(mid 342.66378 -234.721484)
		(end 342.381078 -234.645708)
		(width 0.088646)
		(layer "In6.Cu")
		(net "M_D_CPU0_SB_DQ<16>")
	)
	(arc
		(start 343.603834 -234.15625)
		(mid 343.295003 -234.415813)
		(end 342.958674 -234.638596)
		(width 0.088646)
		(layer "In6.Cu")
		(net "M_D_CPU0_SB_DQ<16>")
	)
	(arc
		(start 333.068676 -233.838242)
		(mid 332.790244 -233.908088)
		(end 332.513432 -233.832146)
		(width 0.088646)
		(layer "In6.Cu")
		(net "M_D_CPU0_SB_DQ<16>")
	)
	(arc
		(start 337.682078 -234.645708)
		(mid 337.49488 -234.595565)
		(end 337.307682 -234.645708)
		(width 0.088646)
		(layer "In6.Cu")
		(net "M_D_CPU0_SB_DQ<16>")
	)
	(arc
		(start 332.230984 -233.342434)
		(mid 332.183305 -233.159534)
		(end 332.052422 -233.023156)
		(width 0.088646)
		(layer "In6.Cu")
		(net "M_D_CPU0_SB_DQ<16>")
	)
	(arc
		(start 332.507336 -233.82859)
		(mid 332.30486 -233.622067)
		(end 332.230984 -233.342434)
		(width 0.088646)
		(layer "In6.Cu")
		(net "M_D_CPU0_SB_DQ<16>")
	)
	(arc
		(start 335.520284 -234.149392)
		(mid 335.468308 -233.965993)
		(end 335.332832 -233.831892)
		(width 0.088646)
		(layer "In6.Cu")
		(net "M_D_CPU0_SB_DQ<16>")
	)
	(arc
		(start 337.29295 -234.654344)
		(mid 337.016475 -234.721664)
		(end 336.742278 -234.645708)
		(width 0.088646)
		(layer "In6.Cu")
		(net "M_D_CPU0_SB_DQ<16>")
	)
	(segment
		(start 261.87781 -214.316564)
		(end 260.180582 -214.316564)
		(width 0.20066)
		(layer "F.Cu")
		(net "M_D_CPU0_SB_DQ<15>")
	)
	(segment
		(start 262.514334 -214.741506)
		(end 262.50011 -214.75573)
		(width 0.101854)
		(layer "F.Cu")
		(net "M_D_CPU0_SB_DQ<15>")
	)
	(segment
		(start 266.90828 -214.316564)
		(end 266.700762 -214.524082)
		(width 0.20066)
		(layer "F.Cu")
		(net "M_D_CPU0_SB_DQ<15>")
	)
	(segment
		(start 347.832934 -233.87812)
		(end 347.83268 -233.877866)
		(width 0.20066)
		(layer "F.Cu")
		(net "M_D_CPU0_SB_DQ<15>")
	)
	(segment
		(start 262.003794 -214.442548)
		(end 261.87781 -214.316564)
		(width 0.20066)
		(layer "F.Cu")
		(net "M_D_CPU0_SB_DQ<15>")
	)
	(segment
		(start 264.825226 -214.741506)
		(end 262.752332 -214.741506)
		(width 0.1016)
		(layer "F.Cu")
		(net "M_D_CPU0_SB_DQ<15>")
	)
	(segment
		(start 267.724382 -214.316564)
		(end 266.90828 -214.316564)
		(width 0.20066)
		(layer "F.Cu")
		(net "M_D_CPU0_SB_DQ<15>")
	)
	(segment
		(start 265.64717 -214.312246)
		(end 265.518646 -214.44077)
		(width 0.20066)
		(layer "F.Cu")
		(net "M_D_CPU0_SB_DQ<15>")
	)
	(segment
		(start 265.518646 -214.592408)
		(end 265.369548 -214.741506)
		(width 0.20066)
		(layer "F.Cu")
		(net "M_D_CPU0_SB_DQ<15>")
	)
	(segment
		(start 262.50011 -214.75573)
		(end 262.146288 -214.75573)
		(width 0.20066)
		(layer "F.Cu")
		(net "M_D_CPU0_SB_DQ<15>")
	)
	(segment
		(start 262.146288 -214.75573)
		(end 262.003794 -214.613236)
		(width 0.20066)
		(layer "F.Cu")
		(net "M_D_CPU0_SB_DQ<15>")
	)
	(segment
		(start 265.518646 -214.44077)
		(end 265.518646 -214.592408)
		(width 0.20066)
		(layer "F.Cu")
		(net "M_D_CPU0_SB_DQ<15>")
	)
	(segment
		(start 268.829282 -214.316564)
		(end 267.724382 -214.316564)
		(width 0.20066)
		(layer "F.Cu")
		(net "M_D_CPU0_SB_DQ<15>")
	)
	(segment
		(start 266.042394 -214.312246)
		(end 265.64717 -214.312246)
		(width 0.20066)
		(layer "F.Cu")
		(net "M_D_CPU0_SB_DQ<15>")
	)
	(segment
		(start 347.83268 -233.877866)
		(end 347.83268 -233.34218)
		(width 0.20066)
		(layer "F.Cu")
		(net "M_D_CPU0_SB_DQ<15>")
	)
	(segment
		(start 262.003794 -214.613236)
		(end 262.003794 -214.442548)
		(width 0.20066)
		(layer "F.Cu")
		(net "M_D_CPU0_SB_DQ<15>")
	)
	(segment
		(start 262.752332 -214.741506)
		(end 262.514334 -214.741506)
		(width 0.101854)
		(layer "F.Cu")
		(net "M_D_CPU0_SB_DQ<15>")
	)
	(segment
		(start 265.369548 -214.741506)
		(end 264.825226 -214.741506)
		(width 0.20066)
		(layer "F.Cu")
		(net "M_D_CPU0_SB_DQ<15>")
	)
	(segment
		(start 266.700762 -214.524082)
		(end 266.25423 -214.524082)
		(width 0.20066)
		(layer "F.Cu")
		(net "M_D_CPU0_SB_DQ<15>")
	)
	(segment
		(start 266.25423 -214.524082)
		(end 266.042394 -214.312246)
		(width 0.20066)
		(layer "F.Cu")
		(net "M_D_CPU0_SB_DQ<15>")
	)
	(segment
		(start 334.488282 -230.41102)
		(end 334.47355 -230.402384)
		(width 0.088646)
		(layer "In11.Cu")
		(net "M_D_CPU0_SB_DQ<15>")
	)
	(segment
		(start 314.65393 -210.719416)
		(end 313.884564 -210.719416)
		(width 0.18288)
		(layer "In11.Cu")
		(net "M_D_CPU0_SB_DQ<15>")
	)
	(segment
		(start 270.725646 -210.075018)
		(end 270.45285 -210.075018)
		(width 0.18288)
		(layer "In11.Cu")
		(net "M_D_CPU0_SB_DQ<15>")
	)
	(segment
		(start 319.065148 -217.783156)
		(end 317.189358 -213.254844)
		(width 0.18288)
		(layer "In11.Cu")
		(net "M_D_CPU0_SB_DQ<15>")
	)
	(segment
		(start 270.948658 -209.852006)
		(end 270.725646 -210.075018)
		(width 0.18288)
		(layer "In11.Cu")
		(net "M_D_CPU0_SB_DQ<15>")
	)
	(segment
		(start 269.420594 -210.532726)
		(end 269.420594 -213.725252)
		(width 0.18288)
		(layer "In11.Cu")
		(net "M_D_CPU0_SB_DQ<15>")
	)
	(segment
		(start 304.425096 -207.007968)
		(end 302.812196 -205.395068)
		(width 0.18288)
		(layer "In11.Cu")
		(net "M_D_CPU0_SB_DQ<15>")
	)
	(segment
		(start 275.55825 -207.131666)
		(end 275.55825 -207.531208)
		(width 0.18288)
		(layer "In11.Cu")
		(net "M_D_CPU0_SB_DQ<15>")
	)
	(segment
		(start 270.948658 -209.57921)
		(end 270.948658 -209.852006)
		(width 0.18288)
		(layer "In11.Cu")
		(net "M_D_CPU0_SB_DQ<15>")
	)
	(segment
		(start 317.189358 -213.254844)
		(end 314.65393 -210.719416)
		(width 0.18288)
		(layer "In11.Cu")
		(net "M_D_CPU0_SB_DQ<15>")
	)
	(segment
		(start 311.043574 -207.878426)
		(end 307.827426 -207.878426)
		(width 0.18288)
		(layer "In11.Cu")
		(net "M_D_CPU0_SB_DQ<15>")
	)
	(segment
		(start 338.247736 -230.41102)
		(end 338.237322 -230.404924)
		(width 0.088646)
		(layer "In11.Cu")
		(net "M_D_CPU0_SB_DQ<15>")
	)
	(segment
		(start 281.103578 -206.37627)
		(end 280.972006 -206.244698)
		(width 0.18288)
		(layer "In11.Cu")
		(net "M_D_CPU0_SB_DQ<15>")
	)
	(segment
		(start 269.420594 -213.725252)
		(end 268.829282 -214.316564)
		(width 0.18288)
		(layer "In11.Cu")
		(net "M_D_CPU0_SB_DQ<15>")
	)
	(segment
		(start 275.36521 -207.724248)
		(end 275.05025 -207.724248)
		(width 0.18288)
		(layer "In11.Cu")
		(net "M_D_CPU0_SB_DQ<15>")
	)
	(segment
		(start 287.766506 -205.394814)
		(end 283.111956 -205.394814)
		(width 0.18288)
		(layer "In11.Cu")
		(net "M_D_CPU0_SB_DQ<15>")
	)
	(segment
		(start 270.45285 -210.075018)
		(end 270.301974 -209.924142)
		(width 0.18288)
		(layer "In11.Cu")
		(net "M_D_CPU0_SB_DQ<15>")
	)
	(segment
		(start 333.548482 -230.41102)
		(end 333.53375 -230.402384)
		(width 0.088646)
		(layer "In11.Cu")
		(net "M_D_CPU0_SB_DQ<15>")
	)
	(segment
		(start 313.884564 -210.719416)
		(end 311.043574 -207.878426)
		(width 0.18288)
		(layer "In11.Cu")
		(net "M_D_CPU0_SB_DQ<15>")
	)
	(segment
		(start 298.154598 -205.395068)
		(end 297.306238 -206.243428)
		(width 0.18288)
		(layer "In11.Cu")
		(net "M_D_CPU0_SB_DQ<15>")
	)
	(segment
		(start 342.952578 -230.414576)
		(end 342.946482 -230.41102)
		(width 0.088646)
		(layer "In11.Cu")
		(net "M_D_CPU0_SB_DQ<15>")
	)
	(segment
		(start 347.83268 -233.34218)
		(end 347.520006 -233.34218)
		(width 0.088646)
		(layer "In11.Cu")
		(net "M_D_CPU0_SB_DQ<15>")
	)
	(segment
		(start 332.326234 -230.335328)
		(end 332.200758 -230.335328)
		(width 0.088646)
		(layer "In11.Cu")
		(net "M_D_CPU0_SB_DQ<15>")
	)
	(segment
		(start 336.367882 -230.41102)
		(end 336.35315 -230.402384)
		(width 0.088646)
		(layer "In11.Cu")
		(net "M_D_CPU0_SB_DQ<15>")
	)
	(segment
		(start 331.302868 -228.939598)
		(end 330.56957 -228.2063)
		(width 0.088646)
		(layer "In11.Cu")
		(net "M_D_CPU0_SB_DQ<15>")
	)
	(segment
		(start 337.307682 -230.41102)
		(end 337.29295 -230.402384)
		(width 0.088646)
		(layer "In11.Cu")
		(net "M_D_CPU0_SB_DQ<15>")
	)
	(segment
		(start 274.66417 -206.938626)
		(end 273.014694 -206.938626)
		(width 0.18288)
		(layer "In11.Cu")
		(net "M_D_CPU0_SB_DQ<15>")
	)
	(segment
		(start 343.416636 -231.224836)
		(end 343.407746 -231.219756)
		(width 0.088646)
		(layer "In11.Cu")
		(net "M_D_CPU0_SB_DQ<15>")
	)
	(segment
		(start 291.958776 -206.253588)
		(end 288.62528 -206.253588)
		(width 0.18288)
		(layer "In11.Cu")
		(net "M_D_CPU0_SB_DQ<15>")
	)
	(segment
		(start 270.797782 -209.428334)
		(end 270.948658 -209.57921)
		(width 0.18288)
		(layer "In11.Cu")
		(net "M_D_CPU0_SB_DQ<15>")
	)
	(segment
		(start 270.029178 -209.924142)
		(end 269.420594 -210.532726)
		(width 0.18288)
		(layer "In11.Cu")
		(net "M_D_CPU0_SB_DQ<15>")
	)
	(segment
		(start 341.066882 -230.41102)
		(end 341.05215 -230.402384)
		(width 0.088646)
		(layer "In11.Cu")
		(net "M_D_CPU0_SB_DQ<15>")
	)
	(segment
		(start 275.55825 -207.531208)
		(end 275.36521 -207.724248)
		(width 0.18288)
		(layer "In11.Cu")
		(net "M_D_CPU0_SB_DQ<15>")
	)
	(segment
		(start 342.006682 -230.41102)
		(end 341.99195 -230.402384)
		(width 0.088646)
		(layer "In11.Cu")
		(net "M_D_CPU0_SB_DQ<15>")
	)
	(segment
		(start 346.620592 -232.846626)
		(end 346.610178 -232.852722)
		(width 0.088646)
		(layer "In11.Cu")
		(net "M_D_CPU0_SB_DQ<15>")
	)
	(segment
		(start 331.302868 -229.437438)
		(end 331.302868 -228.939598)
		(width 0.088646)
		(layer "In11.Cu")
		(net "M_D_CPU0_SB_DQ<15>")
	)
	(segment
		(start 306.956968 -207.007968)
		(end 304.425096 -207.007968)
		(width 0.18288)
		(layer "In11.Cu")
		(net "M_D_CPU0_SB_DQ<15>")
	)
	(segment
		(start 330.313538 -228.2063)
		(end 329.488292 -228.2063)
		(width 0.18288)
		(layer "In11.Cu")
		(net "M_D_CPU0_SB_DQ<15>")
	)
	(segment
		(start 347.520006 -233.34218)
		(end 347.454474 -233.276648)
		(width 0.088646)
		(layer "In11.Cu")
		(net "M_D_CPU0_SB_DQ<15>")
	)
	(segment
		(start 340.127082 -230.41102)
		(end 340.11235 -230.402384)
		(width 0.088646)
		(layer "In11.Cu")
		(net "M_D_CPU0_SB_DQ<15>")
	)
	(segment
		(start 342.946482 -230.41102)
		(end 342.93175 -230.402384)
		(width 0.088646)
		(layer "In11.Cu")
		(net "M_D_CPU0_SB_DQ<15>")
	)
	(segment
		(start 330.56957 -228.2063)
		(end 330.313538 -228.2063)
		(width 0.088646)
		(layer "In11.Cu")
		(net "M_D_CPU0_SB_DQ<15>")
	)
	(segment
		(start 274.85721 -207.531208)
		(end 274.85721 -207.131666)
		(width 0.18288)
		(layer "In11.Cu")
		(net "M_D_CPU0_SB_DQ<15>")
	)
	(segment
		(start 346.235782 -232.852722)
		(end 346.225368 -232.846626)
		(width 0.088646)
		(layer "In11.Cu")
		(net "M_D_CPU0_SB_DQ<15>")
	)
	(segment
		(start 280.972006 -206.244698)
		(end 278.966422 -206.244698)
		(width 0.18288)
		(layer "In11.Cu")
		(net "M_D_CPU0_SB_DQ<15>")
	)
	(segment
		(start 332.200758 -230.335328)
		(end 331.302868 -229.437438)
		(width 0.088646)
		(layer "In11.Cu")
		(net "M_D_CPU0_SB_DQ<15>")
	)
	(segment
		(start 335.428082 -230.41102)
		(end 335.41335 -230.402384)
		(width 0.088646)
		(layer "In11.Cu")
		(net "M_D_CPU0_SB_DQ<15>")
	)
	(segment
		(start 282.1305 -206.37627)
		(end 281.103578 -206.37627)
		(width 0.18288)
		(layer "In11.Cu")
		(net "M_D_CPU0_SB_DQ<15>")
	)
	(segment
		(start 270.301974 -209.924142)
		(end 270.029178 -209.924142)
		(width 0.18288)
		(layer "In11.Cu")
		(net "M_D_CPU0_SB_DQ<15>")
	)
	(segment
		(start 288.62528 -206.253588)
		(end 287.766506 -205.394814)
		(width 0.18288)
		(layer "In11.Cu")
		(net "M_D_CPU0_SB_DQ<15>")
	)
	(segment
		(start 344.356436 -232.852722)
		(end 344.347546 -232.847642)
		(width 0.088646)
		(layer "In11.Cu")
		(net "M_D_CPU0_SB_DQ<15>")
	)
	(segment
		(start 270.797782 -209.155538)
		(end 270.797782 -209.428334)
		(width 0.18288)
		(layer "In11.Cu")
		(net "M_D_CPU0_SB_DQ<15>")
	)
	(segment
		(start 278.069294 -207.141826)
		(end 277.078694 -207.141826)
		(width 0.18288)
		(layer "In11.Cu")
		(net "M_D_CPU0_SB_DQ<15>")
	)
	(segment
		(start 275.05025 -207.724248)
		(end 274.85721 -207.531208)
		(width 0.18288)
		(layer "In11.Cu")
		(net "M_D_CPU0_SB_DQ<15>")
	)
	(segment
		(start 277.078694 -207.141826)
		(end 276.875494 -206.938626)
		(width 0.18288)
		(layer "In11.Cu")
		(net "M_D_CPU0_SB_DQ<15>")
	)
	(segment
		(start 329.488292 -228.2063)
		(end 319.065148 -217.783156)
		(width 0.18288)
		(layer "In11.Cu")
		(net "M_D_CPU0_SB_DQ<15>")
	)
	(segment
		(start 343.69883 -231.714548)
		(end 343.69883 -231.69245)
		(width 0.088646)
		(layer "In11.Cu")
		(net "M_D_CPU0_SB_DQ<15>")
	)
	(segment
		(start 338.632546 -230.404924)
		(end 338.622132 -230.41102)
		(width 0.088646)
		(layer "In11.Cu")
		(net "M_D_CPU0_SB_DQ<15>")
	)
	(segment
		(start 307.827426 -207.878426)
		(end 306.956968 -207.007968)
		(width 0.18288)
		(layer "In11.Cu")
		(net "M_D_CPU0_SB_DQ<15>")
	)
	(segment
		(start 274.85721 -207.131666)
		(end 274.66417 -206.938626)
		(width 0.18288)
		(layer "In11.Cu")
		(net "M_D_CPU0_SB_DQ<15>")
	)
	(segment
		(start 273.014694 -206.938626)
		(end 270.797782 -209.155538)
		(width 0.18288)
		(layer "In11.Cu")
		(net "M_D_CPU0_SB_DQ<15>")
	)
	(segment
		(start 283.111956 -205.394814)
		(end 282.1305 -206.37627)
		(width 0.18288)
		(layer "In11.Cu")
		(net "M_D_CPU0_SB_DQ<15>")
	)
	(segment
		(start 302.812196 -205.395068)
		(end 298.154598 -205.395068)
		(width 0.18288)
		(layer "In11.Cu")
		(net "M_D_CPU0_SB_DQ<15>")
	)
	(segment
		(start 293.577772 -206.243428)
		(end 293.352728 -206.018384)
		(width 0.18288)
		(layer "In11.Cu")
		(net "M_D_CPU0_SB_DQ<15>")
	)
	(segment
		(start 344.745564 -232.844086)
		(end 344.730832 -232.852722)
		(width 0.088646)
		(layer "In11.Cu")
		(net "M_D_CPU0_SB_DQ<15>")
	)
	(segment
		(start 275.75129 -206.938626)
		(end 275.55825 -207.131666)
		(width 0.18288)
		(layer "In11.Cu")
		(net "M_D_CPU0_SB_DQ<15>")
	)
	(segment
		(start 292.19398 -206.018384)
		(end 291.958776 -206.253588)
		(width 0.18288)
		(layer "In11.Cu")
		(net "M_D_CPU0_SB_DQ<15>")
	)
	(segment
		(start 278.966422 -206.244698)
		(end 278.069294 -207.141826)
		(width 0.18288)
		(layer "In11.Cu")
		(net "M_D_CPU0_SB_DQ<15>")
	)
	(segment
		(start 343.886282 -232.038906)
		(end 343.877392 -232.033826)
		(width 0.088646)
		(layer "In11.Cu")
		(net "M_D_CPU0_SB_DQ<15>")
	)
	(segment
		(start 293.352728 -206.018384)
		(end 292.19398 -206.018384)
		(width 0.18288)
		(layer "In11.Cu")
		(net "M_D_CPU0_SB_DQ<15>")
	)
	(segment
		(start 297.306238 -206.243428)
		(end 293.577772 -206.243428)
		(width 0.18288)
		(layer "In11.Cu")
		(net "M_D_CPU0_SB_DQ<15>")
	)
	(segment
		(start 276.875494 -206.938626)
		(end 275.75129 -206.938626)
		(width 0.18288)
		(layer "In11.Cu")
		(net "M_D_CPU0_SB_DQ<15>")
	)
	(segment
		(start 343.892378 -232.042462)
		(end 343.886282 -232.038906)
		(width 0.088646)
		(layer "In11.Cu")
		(net "M_D_CPU0_SB_DQ<15>")
	)
	(arc
		(start 338.237322 -230.404924)
		(mid 337.95889 -230.335078)
		(end 337.682078 -230.41102)
		(width 0.088646)
		(layer "In11.Cu")
		(net "M_D_CPU0_SB_DQ<15>")
	)
	(arc
		(start 339.561678 -230.41102)
		(mid 339.37448 -230.461163)
		(end 339.187282 -230.41102)
		(width 0.088646)
		(layer "In11.Cu")
		(net "M_D_CPU0_SB_DQ<15>")
	)
	(arc
		(start 343.407746 -231.219756)
		(mid 343.276832 -231.083396)
		(end 343.229184 -230.900478)
		(width 0.088646)
		(layer "In11.Cu")
		(net "M_D_CPU0_SB_DQ<15>")
	)
	(arc
		(start 345.296236 -232.852722)
		(mid 345.022037 -232.776887)
		(end 344.745564 -232.844086)
		(width 0.088646)
		(layer "In11.Cu")
		(net "M_D_CPU0_SB_DQ<15>")
	)
	(arc
		(start 343.877392 -232.033826)
		(mid 343.746478 -231.897466)
		(end 343.69883 -231.714548)
		(width 0.088646)
		(layer "In11.Cu")
		(net "M_D_CPU0_SB_DQ<15>")
	)
	(arc
		(start 346.225368 -232.846626)
		(mid 345.94719 -232.776903)
		(end 345.670632 -232.852722)
		(width 0.088646)
		(layer "In11.Cu")
		(net "M_D_CPU0_SB_DQ<15>")
	)
	(arc
		(start 333.53375 -230.402384)
		(mid 333.257275 -230.335064)
		(end 332.983078 -230.41102)
		(width 0.088646)
		(layer "In11.Cu")
		(net "M_D_CPU0_SB_DQ<15>")
	)
	(arc
		(start 341.05215 -230.402384)
		(mid 340.775675 -230.335064)
		(end 340.501478 -230.41102)
		(width 0.088646)
		(layer "In11.Cu")
		(net "M_D_CPU0_SB_DQ<15>")
	)
	(arc
		(start 347.454474 -233.276648)
		(mid 347.365386 -233.031663)
		(end 347.175836 -232.852722)
		(width 0.088646)
		(layer "In11.Cu")
		(net "M_D_CPU0_SB_DQ<15>")
	)
	(arc
		(start 340.501478 -230.41102)
		(mid 340.31428 -230.461163)
		(end 340.127082 -230.41102)
		(width 0.088646)
		(layer "In11.Cu")
		(net "M_D_CPU0_SB_DQ<15>")
	)
	(arc
		(start 334.862678 -230.41102)
		(mid 334.67548 -230.461163)
		(end 334.488282 -230.41102)
		(width 0.088646)
		(layer "In11.Cu")
		(net "M_D_CPU0_SB_DQ<15>")
	)
	(arc
		(start 339.187282 -230.41102)
		(mid 338.910723 -230.335277)
		(end 338.632546 -230.404924)
		(width 0.088646)
		(layer "In11.Cu")
		(net "M_D_CPU0_SB_DQ<15>")
	)
	(arc
		(start 343.69883 -231.69245)
		(mid 343.617919 -231.422322)
		(end 343.416636 -231.224836)
		(width 0.088646)
		(layer "In11.Cu")
		(net "M_D_CPU0_SB_DQ<15>")
	)
	(arc
		(start 334.47355 -230.402384)
		(mid 334.197075 -230.335064)
		(end 333.922878 -230.41102)
		(width 0.088646)
		(layer "In11.Cu")
		(net "M_D_CPU0_SB_DQ<15>")
	)
	(arc
		(start 344.730832 -232.852722)
		(mid 344.543634 -232.902865)
		(end 344.356436 -232.852722)
		(width 0.088646)
		(layer "In11.Cu")
		(net "M_D_CPU0_SB_DQ<15>")
	)
	(arc
		(start 337.29295 -230.402384)
		(mid 337.016475 -230.335064)
		(end 336.742278 -230.41102)
		(width 0.088646)
		(layer "In11.Cu")
		(net "M_D_CPU0_SB_DQ<15>")
	)
	(arc
		(start 338.622132 -230.41102)
		(mid 338.434934 -230.461163)
		(end 338.247736 -230.41102)
		(width 0.088646)
		(layer "In11.Cu")
		(net "M_D_CPU0_SB_DQ<15>")
	)
	(arc
		(start 336.742278 -230.41102)
		(mid 336.55508 -230.461163)
		(end 336.367882 -230.41102)
		(width 0.088646)
		(layer "In11.Cu")
		(net "M_D_CPU0_SB_DQ<15>")
	)
	(arc
		(start 341.99195 -230.402384)
		(mid 341.715475 -230.335064)
		(end 341.441278 -230.41102)
		(width 0.088646)
		(layer "In11.Cu")
		(net "M_D_CPU0_SB_DQ<15>")
	)
	(arc
		(start 335.41335 -230.402384)
		(mid 335.136875 -230.335064)
		(end 334.862678 -230.41102)
		(width 0.088646)
		(layer "In11.Cu")
		(net "M_D_CPU0_SB_DQ<15>")
	)
	(arc
		(start 341.441278 -230.41102)
		(mid 341.25408 -230.461163)
		(end 341.066882 -230.41102)
		(width 0.088646)
		(layer "In11.Cu")
		(net "M_D_CPU0_SB_DQ<15>")
	)
	(arc
		(start 345.670632 -232.852722)
		(mid 345.483434 -232.902865)
		(end 345.296236 -232.852722)
		(width 0.088646)
		(layer "In11.Cu")
		(net "M_D_CPU0_SB_DQ<15>")
	)
	(arc
		(start 344.168984 -232.528364)
		(mid 344.094993 -232.248798)
		(end 343.892378 -232.042462)
		(width 0.088646)
		(layer "In11.Cu")
		(net "M_D_CPU0_SB_DQ<15>")
	)
	(arc
		(start 344.347546 -232.847642)
		(mid 344.216632 -232.711282)
		(end 344.168984 -232.528364)
		(width 0.088646)
		(layer "In11.Cu")
		(net "M_D_CPU0_SB_DQ<15>")
	)
	(arc
		(start 342.93175 -230.402384)
		(mid 342.655275 -230.335064)
		(end 342.381078 -230.41102)
		(width 0.088646)
		(layer "In11.Cu")
		(net "M_D_CPU0_SB_DQ<15>")
	)
	(arc
		(start 342.381078 -230.41102)
		(mid 342.19388 -230.461163)
		(end 342.006682 -230.41102)
		(width 0.088646)
		(layer "In11.Cu")
		(net "M_D_CPU0_SB_DQ<15>")
	)
	(arc
		(start 333.922878 -230.41102)
		(mid 333.73568 -230.461163)
		(end 333.548482 -230.41102)
		(width 0.088646)
		(layer "In11.Cu")
		(net "M_D_CPU0_SB_DQ<15>")
	)
	(arc
		(start 337.682078 -230.41102)
		(mid 337.49488 -230.461163)
		(end 337.307682 -230.41102)
		(width 0.088646)
		(layer "In11.Cu")
		(net "M_D_CPU0_SB_DQ<15>")
	)
	(arc
		(start 340.11235 -230.402384)
		(mid 339.835875 -230.335064)
		(end 339.561678 -230.41102)
		(width 0.088646)
		(layer "In11.Cu")
		(net "M_D_CPU0_SB_DQ<15>")
	)
	(arc
		(start 336.35315 -230.402384)
		(mid 336.076675 -230.335064)
		(end 335.802478 -230.41102)
		(width 0.088646)
		(layer "In11.Cu")
		(net "M_D_CPU0_SB_DQ<15>")
	)
	(arc
		(start 332.608682 -230.41102)
		(mid 332.47244 -230.354586)
		(end 332.326234 -230.335328)
		(width 0.088646)
		(layer "In11.Cu")
		(net "M_D_CPU0_SB_DQ<15>")
	)
	(arc
		(start 332.983078 -230.41102)
		(mid 332.79588 -230.461163)
		(end 332.608682 -230.41102)
		(width 0.088646)
		(layer "In11.Cu")
		(net "M_D_CPU0_SB_DQ<15>")
	)
	(arc
		(start 343.229184 -230.900478)
		(mid 343.155193 -230.620912)
		(end 342.952578 -230.414576)
		(width 0.088646)
		(layer "In11.Cu")
		(net "M_D_CPU0_SB_DQ<15>")
	)
	(arc
		(start 347.175836 -232.852722)
		(mid 346.899023 -232.776852)
		(end 346.620592 -232.846626)
		(width 0.088646)
		(layer "In11.Cu")
		(net "M_D_CPU0_SB_DQ<15>")
	)
	(arc
		(start 335.802478 -230.41102)
		(mid 335.61528 -230.461163)
		(end 335.428082 -230.41102)
		(width 0.088646)
		(layer "In11.Cu")
		(net "M_D_CPU0_SB_DQ<15>")
	)
	(arc
		(start 346.610178 -232.852722)
		(mid 346.42298 -232.902865)
		(end 346.235782 -232.852722)
		(width 0.088646)
		(layer "In11.Cu")
		(net "M_D_CPU0_SB_DQ<15>")
	)
	(segment
		(start 262.50011 -215.581484)
		(end 261.762748 -215.581484)
		(width 0.20066)
		(layer "F.Cu")
		(net "M_D_CPU0_SB_DQ<14>")
	)
	(segment
		(start 264.825226 -215.591644)
		(end 262.765286 -215.591644)
		(width 0.1016)
		(layer "F.Cu")
		(net "M_D_CPU0_SB_DQ<14>")
	)
	(segment
		(start 262.51027 -215.591644)
		(end 262.50011 -215.581484)
		(width 0.101854)
		(layer "F.Cu")
		(net "M_D_CPU0_SB_DQ<14>")
	)
	(segment
		(start 268.829282 -216.016586)
		(end 267.724382 -216.016586)
		(width 0.20066)
		(layer "F.Cu")
		(net "M_D_CPU0_SB_DQ<14>")
	)
	(segment
		(start 266.197842 -216.228422)
		(end 265.769344 -216.228422)
		(width 0.20066)
		(layer "F.Cu")
		(net "M_D_CPU0_SB_DQ<14>")
	)
	(segment
		(start 267.724382 -216.016586)
		(end 266.409678 -216.016586)
		(width 0.20066)
		(layer "F.Cu")
		(net "M_D_CPU0_SB_DQ<14>")
	)
	(segment
		(start 265.601958 -216.061036)
		(end 265.601958 -215.735408)
		(width 0.20066)
		(layer "F.Cu")
		(net "M_D_CPU0_SB_DQ<14>")
	)
	(segment
		(start 261.327646 -216.016586)
		(end 260.180582 -216.016586)
		(width 0.20066)
		(layer "F.Cu")
		(net "M_D_CPU0_SB_DQ<14>")
	)
	(segment
		(start 265.458194 -215.591644)
		(end 264.825226 -215.591644)
		(width 0.20066)
		(layer "F.Cu")
		(net "M_D_CPU0_SB_DQ<14>")
	)
	(segment
		(start 265.769344 -216.228422)
		(end 265.601958 -216.061036)
		(width 0.20066)
		(layer "F.Cu")
		(net "M_D_CPU0_SB_DQ<14>")
	)
	(segment
		(start 348.302834 -234.691936)
		(end 348.302834 -234.15625)
		(width 0.20066)
		(layer "F.Cu")
		(net "M_D_CPU0_SB_DQ<14>")
	)
	(segment
		(start 266.409678 -216.016586)
		(end 266.197842 -216.228422)
		(width 0.20066)
		(layer "F.Cu")
		(net "M_D_CPU0_SB_DQ<14>")
	)
	(segment
		(start 262.765286 -215.591644)
		(end 262.51027 -215.591644)
		(width 0.101854)
		(layer "F.Cu")
		(net "M_D_CPU0_SB_DQ<14>")
	)
	(segment
		(start 265.601958 -215.735408)
		(end 265.458194 -215.591644)
		(width 0.20066)
		(layer "F.Cu")
		(net "M_D_CPU0_SB_DQ<14>")
	)
	(segment
		(start 261.762748 -215.581484)
		(end 261.327646 -216.016586)
		(width 0.20066)
		(layer "F.Cu")
		(net "M_D_CPU0_SB_DQ<14>")
	)
	(segment
		(start 348.30258 -234.69219)
		(end 348.302834 -234.691936)
		(width 0.20066)
		(layer "F.Cu")
		(net "M_D_CPU0_SB_DQ<14>")
	)
	(segment
		(start 273.635978 -208.857342)
		(end 271.643094 -210.850226)
		(width 0.18288)
		(layer "In11.Cu")
		(net "M_D_CPU0_SB_DQ<14>")
	)
	(segment
		(start 347.645482 -233.666538)
		(end 347.63075 -233.657902)
		(width 0.088646)
		(layer "In11.Cu")
		(net "M_D_CPU0_SB_DQ<14>")
	)
	(segment
		(start 344.826082 -233.666538)
		(end 344.81135 -233.657902)
		(width 0.088646)
		(layer "In11.Cu")
		(net "M_D_CPU0_SB_DQ<14>")
	)
	(segment
		(start 292.082728 -207.962246)
		(end 288.059114 -207.962246)
		(width 0.18288)
		(layer "In11.Cu")
		(net "M_D_CPU0_SB_DQ<14>")
	)
	(segment
		(start 336.287364 -231.2162)
		(end 336.272632 -231.224836)
		(width 0.088646)
		(layer "In11.Cu")
		(net "M_D_CPU0_SB_DQ<14>")
	)
	(segment
		(start 342.289384 -232.528364)
		(end 342.289384 -232.518458)
		(width 0.088646)
		(layer "In11.Cu")
		(net "M_D_CPU0_SB_DQ<14>")
	)
	(segment
		(start 341.819484 -231.714548)
		(end 341.819484 -231.700324)
		(width 0.088646)
		(layer "In11.Cu")
		(net "M_D_CPU0_SB_DQ<14>")
	)
	(segment
		(start 279.210008 -207.94218)
		(end 278.294846 -208.857342)
		(width 0.18288)
		(layer "In11.Cu")
		(net "M_D_CPU0_SB_DQ<14>")
	)
	(segment
		(start 293.27729 -207.94218)
		(end 293.134034 -207.798924)
		(width 0.18288)
		(layer "In11.Cu")
		(net "M_D_CPU0_SB_DQ<14>")
	)
	(segment
		(start 282.52801 -207.94218)
		(end 282.009342 -207.94218)
		(width 0.18288)
		(layer "In11.Cu")
		(net "M_D_CPU0_SB_DQ<14>")
	)
	(segment
		(start 271.450054 -213.501224)
		(end 271.30248 -213.501224)
		(width 0.18288)
		(layer "In11.Cu")
		(net "M_D_CPU0_SB_DQ<14>")
	)
	(segment
		(start 302.185324 -207.094836)
		(end 298.371006 -207.094836)
		(width 0.18288)
		(layer "In11.Cu")
		(net "M_D_CPU0_SB_DQ<14>")
	)
	(segment
		(start 307.123846 -209.683858)
		(end 306.23383 -208.793842)
		(width 0.18288)
		(layer "In11.Cu")
		(net "M_D_CPU0_SB_DQ<14>")
	)
	(segment
		(start 313.757056 -212.298788)
		(end 312.638694 -211.180426)
		(width 0.18288)
		(layer "In11.Cu")
		(net "M_D_CPU0_SB_DQ<14>")
	)
	(segment
		(start 271.30248 -213.501224)
		(end 271.10944 -213.694264)
		(width 0.18288)
		(layer "In11.Cu")
		(net "M_D_CPU0_SB_DQ<14>")
	)
	(segment
		(start 340.046564 -231.2162)
		(end 340.031832 -231.224836)
		(width 0.088646)
		(layer "In11.Cu")
		(net "M_D_CPU0_SB_DQ<14>")
	)
	(segment
		(start 293.134034 -207.798924)
		(end 292.24605 -207.798924)
		(width 0.18288)
		(layer "In11.Cu")
		(net "M_D_CPU0_SB_DQ<14>")
	)
	(segment
		(start 311.648094 -211.180426)
		(end 310.151526 -209.683858)
		(width 0.18288)
		(layer "In11.Cu")
		(net "M_D_CPU0_SB_DQ<14>")
	)
	(segment
		(start 281.338782 -208.221326)
		(end 281.059636 -207.94218)
		(width 0.18288)
		(layer "In11.Cu")
		(net "M_D_CPU0_SB_DQ<14>")
	)
	(segment
		(start 271.10944 -214.009224)
		(end 271.30248 -214.202264)
		(width 0.18288)
		(layer "In11.Cu")
		(net "M_D_CPU0_SB_DQ<14>")
	)
	(segment
		(start 330.886308 -229.7557)
		(end 330.886308 -229.478586)
		(width 0.088646)
		(layer "In11.Cu")
		(net "M_D_CPU0_SB_DQ<14>")
	)
	(segment
		(start 339.102192 -231.21874)
		(end 339.091778 -231.224836)
		(width 0.088646)
		(layer "In11.Cu")
		(net "M_D_CPU0_SB_DQ<14>")
	)
	(segment
		(start 332.039976 -230.909368)
		(end 330.886308 -229.7557)
		(width 0.088646)
		(layer "In11.Cu")
		(net "M_D_CPU0_SB_DQ<14>")
	)
	(segment
		(start 271.10944 -213.694264)
		(end 271.10944 -214.009224)
		(width 0.18288)
		(layer "In11.Cu")
		(net "M_D_CPU0_SB_DQ<14>")
	)
	(segment
		(start 281.059636 -207.94218)
		(end 279.210008 -207.94218)
		(width 0.18288)
		(layer "In11.Cu")
		(net "M_D_CPU0_SB_DQ<14>")
	)
	(segment
		(start 332.039976 -231.114854)
		(end 332.039976 -230.909368)
		(width 0.088646)
		(layer "In11.Cu")
		(net "M_D_CPU0_SB_DQ<14>")
	)
	(segment
		(start 314.478162 -212.298788)
		(end 313.757056 -212.298788)
		(width 0.18288)
		(layer "In11.Cu")
		(net "M_D_CPU0_SB_DQ<14>")
	)
	(segment
		(start 271.643094 -214.878158)
		(end 271.062704 -215.458548)
		(width 0.18288)
		(layer "In11.Cu")
		(net "M_D_CPU0_SB_DQ<14>")
	)
	(segment
		(start 338.162646 -231.21874)
		(end 338.152232 -231.224836)
		(width 0.088646)
		(layer "In11.Cu")
		(net "M_D_CPU0_SB_DQ<14>")
	)
	(segment
		(start 271.643094 -214.395304)
		(end 271.643094 -214.878158)
		(width 0.18288)
		(layer "In11.Cu")
		(net "M_D_CPU0_SB_DQ<14>")
	)
	(segment
		(start 345.766136 -233.666538)
		(end 345.755722 -233.660442)
		(width 0.088646)
		(layer "In11.Cu")
		(net "M_D_CPU0_SB_DQ<14>")
	)
	(segment
		(start 332.200758 -231.275636)
		(end 332.039976 -231.114854)
		(width 0.088646)
		(layer "In11.Cu")
		(net "M_D_CPU0_SB_DQ<14>")
	)
	(segment
		(start 271.30248 -212.099144)
		(end 271.10944 -212.292184)
		(width 0.18288)
		(layer "In11.Cu")
		(net "M_D_CPU0_SB_DQ<14>")
	)
	(segment
		(start 269.38732 -215.458548)
		(end 268.829282 -216.016586)
		(width 0.18288)
		(layer "In11.Cu")
		(net "M_D_CPU0_SB_DQ<14>")
	)
	(segment
		(start 271.643094 -211.906104)
		(end 271.450054 -212.099144)
		(width 0.18288)
		(layer "In11.Cu")
		(net "M_D_CPU0_SB_DQ<14>")
	)
	(segment
		(start 342.006936 -232.038906)
		(end 341.998046 -232.033826)
		(width 0.088646)
		(layer "In11.Cu")
		(net "M_D_CPU0_SB_DQ<14>")
	)
	(segment
		(start 330.630022 -229.2223)
		(end 330.313538 -229.2223)
		(width 0.088646)
		(layer "In11.Cu")
		(net "M_D_CPU0_SB_DQ<14>")
	)
	(segment
		(start 292.24605 -207.798924)
		(end 292.082728 -207.962246)
		(width 0.18288)
		(layer "In11.Cu")
		(net "M_D_CPU0_SB_DQ<14>")
	)
	(segment
		(start 287.190688 -207.09382)
		(end 283.37637 -207.09382)
		(width 0.18288)
		(layer "In11.Cu")
		(net "M_D_CPU0_SB_DQ<14>")
	)
	(segment
		(start 343.886282 -233.666538)
		(end 343.87155 -233.657902)
		(width 0.088646)
		(layer "In11.Cu")
		(net "M_D_CPU0_SB_DQ<14>")
	)
	(segment
		(start 342.946482 -233.666538)
		(end 342.937592 -233.661458)
		(width 0.088646)
		(layer "In11.Cu")
		(net "M_D_CPU0_SB_DQ<14>")
	)
	(segment
		(start 310.151526 -209.683858)
		(end 307.123846 -209.683858)
		(width 0.18288)
		(layer "In11.Cu")
		(net "M_D_CPU0_SB_DQ<14>")
	)
	(segment
		(start 271.10944 -212.292184)
		(end 271.10944 -212.607144)
		(width 0.18288)
		(layer "In11.Cu")
		(net "M_D_CPU0_SB_DQ<14>")
	)
	(segment
		(start 297.418252 -208.04759)
		(end 296.312336 -208.04759)
		(width 0.18288)
		(layer "In11.Cu")
		(net "M_D_CPU0_SB_DQ<14>")
	)
	(segment
		(start 271.450054 -214.202264)
		(end 271.643094 -214.395304)
		(width 0.18288)
		(layer "In11.Cu")
		(net "M_D_CPU0_SB_DQ<14>")
	)
	(segment
		(start 306.23383 -208.793842)
		(end 303.88433 -208.793842)
		(width 0.18288)
		(layer "In11.Cu")
		(net "M_D_CPU0_SB_DQ<14>")
	)
	(segment
		(start 271.10944 -212.607144)
		(end 271.30248 -212.800184)
		(width 0.18288)
		(layer "In11.Cu")
		(net "M_D_CPU0_SB_DQ<14>")
	)
	(segment
		(start 271.30248 -214.202264)
		(end 271.450054 -214.202264)
		(width 0.18288)
		(layer "In11.Cu")
		(net "M_D_CPU0_SB_DQ<14>")
	)
	(segment
		(start 316.493398 -214.314024)
		(end 314.478162 -212.298788)
		(width 0.18288)
		(layer "In11.Cu")
		(net "M_D_CPU0_SB_DQ<14>")
	)
	(segment
		(start 332.326234 -231.275636)
		(end 332.200758 -231.275636)
		(width 0.088646)
		(layer "In11.Cu")
		(net "M_D_CPU0_SB_DQ<14>")
	)
	(segment
		(start 330.313538 -229.2223)
		(end 329.030838 -229.2223)
		(width 0.18288)
		(layer "In11.Cu")
		(net "M_D_CPU0_SB_DQ<14>")
	)
	(segment
		(start 271.062704 -215.458548)
		(end 269.38732 -215.458548)
		(width 0.18288)
		(layer "In11.Cu")
		(net "M_D_CPU0_SB_DQ<14>")
	)
	(segment
		(start 303.88433 -208.793842)
		(end 302.185324 -207.094836)
		(width 0.18288)
		(layer "In11.Cu")
		(net "M_D_CPU0_SB_DQ<14>")
	)
	(segment
		(start 283.37637 -207.09382)
		(end 282.52801 -207.94218)
		(width 0.18288)
		(layer "In11.Cu")
		(net "M_D_CPU0_SB_DQ<14>")
	)
	(segment
		(start 296.206926 -207.94218)
		(end 293.27729 -207.94218)
		(width 0.18288)
		(layer "In11.Cu")
		(net "M_D_CPU0_SB_DQ<14>")
	)
	(segment
		(start 271.643094 -212.993224)
		(end 271.643094 -213.308184)
		(width 0.18288)
		(layer "In11.Cu")
		(net "M_D_CPU0_SB_DQ<14>")
	)
	(segment
		(start 312.638694 -211.180426)
		(end 311.648094 -211.180426)
		(width 0.18288)
		(layer "In11.Cu")
		(net "M_D_CPU0_SB_DQ<14>")
	)
	(segment
		(start 281.730196 -208.221326)
		(end 281.338782 -208.221326)
		(width 0.18288)
		(layer "In11.Cu")
		(net "M_D_CPU0_SB_DQ<14>")
	)
	(segment
		(start 288.059114 -207.962246)
		(end 287.190688 -207.09382)
		(width 0.18288)
		(layer "In11.Cu")
		(net "M_D_CPU0_SB_DQ<14>")
	)
	(segment
		(start 340.986364 -231.2162)
		(end 340.971632 -231.224836)
		(width 0.088646)
		(layer "In11.Cu")
		(net "M_D_CPU0_SB_DQ<14>")
	)
	(segment
		(start 296.312336 -208.04759)
		(end 296.206926 -207.94218)
		(width 0.18288)
		(layer "In11.Cu")
		(net "M_D_CPU0_SB_DQ<14>")
	)
	(segment
		(start 278.294846 -208.857342)
		(end 273.635978 -208.857342)
		(width 0.18288)
		(layer "In11.Cu")
		(net "M_D_CPU0_SB_DQ<14>")
	)
	(segment
		(start 329.030838 -229.2223)
		(end 318.170306 -218.361768)
		(width 0.18288)
		(layer "In11.Cu")
		(net "M_D_CPU0_SB_DQ<14>")
	)
	(segment
		(start 271.30248 -212.800184)
		(end 271.450054 -212.800184)
		(width 0.18288)
		(layer "In11.Cu")
		(net "M_D_CPU0_SB_DQ<14>")
	)
	(segment
		(start 342.476836 -232.852722)
		(end 342.467946 -232.847642)
		(width 0.088646)
		(layer "In11.Cu")
		(net "M_D_CPU0_SB_DQ<14>")
	)
	(segment
		(start 271.450054 -212.099144)
		(end 271.30248 -212.099144)
		(width 0.18288)
		(layer "In11.Cu")
		(net "M_D_CPU0_SB_DQ<14>")
	)
	(segment
		(start 342.75903 -233.34218)
		(end 342.75903 -233.326686)
		(width 0.088646)
		(layer "In11.Cu")
		(net "M_D_CPU0_SB_DQ<14>")
	)
	(segment
		(start 330.886308 -229.478586)
		(end 330.630022 -229.2223)
		(width 0.088646)
		(layer "In11.Cu")
		(net "M_D_CPU0_SB_DQ<14>")
	)
	(segment
		(start 271.450054 -212.800184)
		(end 271.643094 -212.993224)
		(width 0.18288)
		(layer "In11.Cu")
		(net "M_D_CPU0_SB_DQ<14>")
	)
	(segment
		(start 271.643094 -210.850226)
		(end 271.643094 -211.906104)
		(width 0.18288)
		(layer "In11.Cu")
		(net "M_D_CPU0_SB_DQ<14>")
	)
	(segment
		(start 337.227164 -231.2162)
		(end 337.212432 -231.224836)
		(width 0.088646)
		(layer "In11.Cu")
		(net "M_D_CPU0_SB_DQ<14>")
	)
	(segment
		(start 271.643094 -213.308184)
		(end 271.450054 -213.501224)
		(width 0.18288)
		(layer "In11.Cu")
		(net "M_D_CPU0_SB_DQ<14>")
	)
	(segment
		(start 282.009342 -207.94218)
		(end 281.730196 -208.221326)
		(width 0.18288)
		(layer "In11.Cu")
		(net "M_D_CPU0_SB_DQ<14>")
	)
	(segment
		(start 346.705682 -233.666538)
		(end 346.695268 -233.660442)
		(width 0.088646)
		(layer "In11.Cu")
		(net "M_D_CPU0_SB_DQ<14>")
	)
	(segment
		(start 318.170306 -218.361768)
		(end 316.493398 -214.314024)
		(width 0.18288)
		(layer "In11.Cu")
		(net "M_D_CPU0_SB_DQ<14>")
	)
	(segment
		(start 298.371006 -207.094836)
		(end 297.418252 -208.04759)
		(width 0.18288)
		(layer "In11.Cu")
		(net "M_D_CPU0_SB_DQ<14>")
	)
	(arc
		(start 345.755722 -233.660442)
		(mid 345.47729 -233.590628)
		(end 345.200478 -233.666538)
		(width 0.088646)
		(layer "In11.Cu")
		(net "M_D_CPU0_SB_DQ<14>")
	)
	(arc
		(start 342.75903 -233.326686)
		(mid 342.67966 -233.052952)
		(end 342.476836 -232.852722)
		(width 0.088646)
		(layer "In11.Cu")
		(net "M_D_CPU0_SB_DQ<14>")
	)
	(arc
		(start 340.971632 -231.224836)
		(mid 340.784434 -231.274979)
		(end 340.597236 -231.224836)
		(width 0.088646)
		(layer "In11.Cu")
		(net "M_D_CPU0_SB_DQ<14>")
	)
	(arc
		(start 347.63075 -233.657902)
		(mid 347.354309 -233.590736)
		(end 347.080078 -233.666538)
		(width 0.088646)
		(layer "In11.Cu")
		(net "M_D_CPU0_SB_DQ<14>")
	)
	(arc
		(start 345.200478 -233.666538)
		(mid 345.01328 -233.716681)
		(end 344.826082 -233.666538)
		(width 0.088646)
		(layer "In11.Cu")
		(net "M_D_CPU0_SB_DQ<14>")
	)
	(arc
		(start 333.078836 -231.224836)
		(mid 332.796134 -231.149094)
		(end 332.513432 -231.224836)
		(width 0.088646)
		(layer "In11.Cu")
		(net "M_D_CPU0_SB_DQ<14>")
	)
	(arc
		(start 339.091778 -231.224836)
		(mid 338.90458 -231.274979)
		(end 338.717382 -231.224836)
		(width 0.088646)
		(layer "In11.Cu")
		(net "M_D_CPU0_SB_DQ<14>")
	)
	(arc
		(start 334.958436 -231.224836)
		(mid 334.675734 -231.149094)
		(end 334.393032 -231.224836)
		(width 0.088646)
		(layer "In11.Cu")
		(net "M_D_CPU0_SB_DQ<14>")
	)
	(arc
		(start 341.819484 -231.700324)
		(mid 341.740343 -231.425701)
		(end 341.537036 -231.224836)
		(width 0.088646)
		(layer "In11.Cu")
		(net "M_D_CPU0_SB_DQ<14>")
	)
	(arc
		(start 334.393032 -231.224836)
		(mid 334.205834 -231.274979)
		(end 334.018636 -231.224836)
		(width 0.088646)
		(layer "In11.Cu")
		(net "M_D_CPU0_SB_DQ<14>")
	)
	(arc
		(start 334.018636 -231.224836)
		(mid 333.735934 -231.149094)
		(end 333.453232 -231.224836)
		(width 0.088646)
		(layer "In11.Cu")
		(net "M_D_CPU0_SB_DQ<14>")
	)
	(arc
		(start 346.695268 -233.660442)
		(mid 346.41709 -233.59075)
		(end 346.140532 -233.666538)
		(width 0.088646)
		(layer "In11.Cu")
		(net "M_D_CPU0_SB_DQ<14>")
	)
	(arc
		(start 335.332832 -231.224836)
		(mid 335.145634 -231.274979)
		(end 334.958436 -231.224836)
		(width 0.088646)
		(layer "In11.Cu")
		(net "M_D_CPU0_SB_DQ<14>")
	)
	(arc
		(start 336.838036 -231.224836)
		(mid 336.563807 -231.148911)
		(end 336.287364 -231.2162)
		(width 0.088646)
		(layer "In11.Cu")
		(net "M_D_CPU0_SB_DQ<14>")
	)
	(arc
		(start 343.87155 -233.657902)
		(mid 343.595109 -233.590736)
		(end 343.320878 -233.666538)
		(width 0.088646)
		(layer "In11.Cu")
		(net "M_D_CPU0_SB_DQ<14>")
	)
	(arc
		(start 343.320878 -233.666538)
		(mid 343.13368 -233.716681)
		(end 342.946482 -233.666538)
		(width 0.088646)
		(layer "In11.Cu")
		(net "M_D_CPU0_SB_DQ<14>")
	)
	(arc
		(start 338.717382 -231.224836)
		(mid 338.440823 -231.149127)
		(end 338.162646 -231.21874)
		(width 0.088646)
		(layer "In11.Cu")
		(net "M_D_CPU0_SB_DQ<14>")
	)
	(arc
		(start 342.467946 -232.847642)
		(mid 342.337032 -232.711282)
		(end 342.289384 -232.528364)
		(width 0.088646)
		(layer "In11.Cu")
		(net "M_D_CPU0_SB_DQ<14>")
	)
	(arc
		(start 337.777836 -231.224836)
		(mid 337.503607 -231.148911)
		(end 337.227164 -231.2162)
		(width 0.088646)
		(layer "In11.Cu")
		(net "M_D_CPU0_SB_DQ<14>")
	)
	(arc
		(start 333.453232 -231.224836)
		(mid 333.266034 -231.274979)
		(end 333.078836 -231.224836)
		(width 0.088646)
		(layer "In11.Cu")
		(net "M_D_CPU0_SB_DQ<14>")
	)
	(arc
		(start 348.302834 -234.15625)
		(mid 347.987648 -233.893286)
		(end 347.645482 -233.666538)
		(width 0.088646)
		(layer "In11.Cu")
		(net "M_D_CPU0_SB_DQ<14>")
	)
	(arc
		(start 338.152232 -231.224836)
		(mid 337.965034 -231.274979)
		(end 337.777836 -231.224836)
		(width 0.088646)
		(layer "In11.Cu")
		(net "M_D_CPU0_SB_DQ<14>")
	)
	(arc
		(start 346.140532 -233.666538)
		(mid 345.953334 -233.716681)
		(end 345.766136 -233.666538)
		(width 0.088646)
		(layer "In11.Cu")
		(net "M_D_CPU0_SB_DQ<14>")
	)
	(arc
		(start 340.031832 -231.224836)
		(mid 339.844634 -231.274979)
		(end 339.657436 -231.224836)
		(width 0.088646)
		(layer "In11.Cu")
		(net "M_D_CPU0_SB_DQ<14>")
	)
	(arc
		(start 332.513432 -231.224836)
		(mid 332.423176 -231.262558)
		(end 332.326234 -231.275636)
		(width 0.088646)
		(layer "In11.Cu")
		(net "M_D_CPU0_SB_DQ<14>")
	)
	(arc
		(start 336.272632 -231.224836)
		(mid 336.085434 -231.274979)
		(end 335.898236 -231.224836)
		(width 0.088646)
		(layer "In11.Cu")
		(net "M_D_CPU0_SB_DQ<14>")
	)
	(arc
		(start 342.289384 -232.518458)
		(mid 342.211273 -232.241509)
		(end 342.006936 -232.038906)
		(width 0.088646)
		(layer "In11.Cu")
		(net "M_D_CPU0_SB_DQ<14>")
	)
	(arc
		(start 335.898236 -231.224836)
		(mid 335.615534 -231.149094)
		(end 335.332832 -231.224836)
		(width 0.088646)
		(layer "In11.Cu")
		(net "M_D_CPU0_SB_DQ<14>")
	)
	(arc
		(start 337.212432 -231.224836)
		(mid 337.025234 -231.274979)
		(end 336.838036 -231.224836)
		(width 0.088646)
		(layer "In11.Cu")
		(net "M_D_CPU0_SB_DQ<14>")
	)
	(arc
		(start 347.080078 -233.666538)
		(mid 346.89288 -233.716681)
		(end 346.705682 -233.666538)
		(width 0.088646)
		(layer "In11.Cu")
		(net "M_D_CPU0_SB_DQ<14>")
	)
	(arc
		(start 344.81135 -233.657902)
		(mid 344.534909 -233.590736)
		(end 344.260678 -233.666538)
		(width 0.088646)
		(layer "In11.Cu")
		(net "M_D_CPU0_SB_DQ<14>")
	)
	(arc
		(start 341.537036 -231.224836)
		(mid 341.262807 -231.148911)
		(end 340.986364 -231.2162)
		(width 0.088646)
		(layer "In11.Cu")
		(net "M_D_CPU0_SB_DQ<14>")
	)
	(arc
		(start 344.260678 -233.666538)
		(mid 344.07348 -233.716681)
		(end 343.886282 -233.666538)
		(width 0.088646)
		(layer "In11.Cu")
		(net "M_D_CPU0_SB_DQ<14>")
	)
	(arc
		(start 342.937592 -233.661458)
		(mid 342.806678 -233.525098)
		(end 342.75903 -233.34218)
		(width 0.088646)
		(layer "In11.Cu")
		(net "M_D_CPU0_SB_DQ<14>")
	)
	(arc
		(start 339.657436 -231.224836)
		(mid 339.380623 -231.149)
		(end 339.102192 -231.21874)
		(width 0.088646)
		(layer "In11.Cu")
		(net "M_D_CPU0_SB_DQ<14>")
	)
	(arc
		(start 341.998046 -232.033826)
		(mid 341.867132 -231.897466)
		(end 341.819484 -231.714548)
		(width 0.088646)
		(layer "In11.Cu")
		(net "M_D_CPU0_SB_DQ<14>")
	)
	(arc
		(start 340.597236 -231.224836)
		(mid 340.323007 -231.148911)
		(end 340.046564 -231.2162)
		(width 0.088646)
		(layer "In11.Cu")
		(net "M_D_CPU0_SB_DQ<14>")
	)
	(segment
		(start 263.624314 -215.166702)
		(end 261.984998 -215.166702)
		(width 0.20066)
		(layer "F.Cu")
		(net "M_D_CPU0_SB_DQ<13>")
	)
	(segment
		(start 257.414776 -215.166702)
		(end 256.080514 -215.166702)
		(width 0.20066)
		(layer "F.Cu")
		(net "M_D_CPU0_SB_DQ<13>")
	)
	(segment
		(start 258.28498 -215.223598)
		(end 258.130548 -215.37803)
		(width 0.20066)
		(layer "F.Cu")
		(net "M_D_CPU0_SB_DQ<13>")
	)
	(segment
		(start 261.560056 -214.74176)
		(end 261.381494 -214.74176)
		(width 0.20066)
		(layer "F.Cu")
		(net "M_D_CPU0_SB_DQ<13>")
	)
	(segment
		(start 346.893134 -233.87812)
		(end 346.89288 -233.877866)
		(width 0.20066)
		(layer "F.Cu")
		(net "M_D_CPU0_SB_DQ<13>")
	)
	(segment
		(start 258.28498 -214.89543)
		(end 258.28498 -215.223598)
		(width 0.20066)
		(layer "F.Cu")
		(net "M_D_CPU0_SB_DQ<13>")
	)
	(segment
		(start 261.381494 -214.74176)
		(end 261.050786 -214.74176)
		(width 0.101854)
		(layer "F.Cu")
		(net "M_D_CPU0_SB_DQ<13>")
	)
	(segment
		(start 258.130548 -215.37803)
		(end 257.626104 -215.37803)
		(width 0.20066)
		(layer "F.Cu")
		(net "M_D_CPU0_SB_DQ<13>")
	)
	(segment
		(start 261.984998 -215.166702)
		(end 261.560056 -214.74176)
		(width 0.20066)
		(layer "F.Cu")
		(net "M_D_CPU0_SB_DQ<13>")
	)
	(segment
		(start 261.050786 -214.74176)
		(end 259.065268 -214.74176)
		(width 0.1016)
		(layer "F.Cu")
		(net "M_D_CPU0_SB_DQ<13>")
	)
	(segment
		(start 257.626104 -215.37803)
		(end 257.414776 -215.166702)
		(width 0.20066)
		(layer "F.Cu")
		(net "M_D_CPU0_SB_DQ<13>")
	)
	(segment
		(start 259.065268 -214.74176)
		(end 259.056378 -214.73287)
		(width 0.1016)
		(layer "F.Cu")
		(net "M_D_CPU0_SB_DQ<13>")
	)
	(segment
		(start 346.89288 -233.877866)
		(end 346.89288 -233.34218)
		(width 0.20066)
		(layer "F.Cu")
		(net "M_D_CPU0_SB_DQ<13>")
	)
	(segment
		(start 259.056378 -214.73287)
		(end 258.44754 -214.73287)
		(width 0.20066)
		(layer "F.Cu")
		(net "M_D_CPU0_SB_DQ<13>")
	)
	(segment
		(start 264.729214 -215.166702)
		(end 263.624314 -215.166702)
		(width 0.20066)
		(layer "F.Cu")
		(net "M_D_CPU0_SB_DQ<13>")
	)
	(segment
		(start 258.44754 -214.73287)
		(end 258.28498 -214.89543)
		(width 0.20066)
		(layer "F.Cu")
		(net "M_D_CPU0_SB_DQ<13>")
	)
	(segment
		(start 339.102192 -230.582216)
		(end 339.091778 -230.57612)
		(width 0.088646)
		(layer "In11.Cu")
		(net "M_D_CPU0_SB_DQ<13>")
	)
	(segment
		(start 269.720314 -214.914226)
		(end 269.545562 -214.739474)
		(width 0.18288)
		(layer "In11.Cu")
		(net "M_D_CPU0_SB_DQ<13>")
	)
	(segment
		(start 343.799922 -232.209086)
		(end 343.791032 -232.204006)
		(width 0.088646)
		(layer "In11.Cu")
		(net "M_D_CPU0_SB_DQ<13>")
	)
	(segment
		(start 270.585692 -211.069428)
		(end 270.585692 -214.569802)
		(width 0.18288)
		(layer "In11.Cu")
		(net "M_D_CPU0_SB_DQ<13>")
	)
	(segment
		(start 294.07866 -207.16113)
		(end 292.287198 -207.16113)
		(width 0.18288)
		(layer "In11.Cu")
		(net "M_D_CPU0_SB_DQ<13>")
	)
	(segment
		(start 282.625546 -206.93507)
		(end 280.734008 -206.93507)
		(width 0.18288)
		(layer "In11.Cu")
		(net "M_D_CPU0_SB_DQ<13>")
	)
	(segment
		(start 340.046564 -230.584756)
		(end 340.031832 -230.57612)
		(width 0.088646)
		(layer "In11.Cu")
		(net "M_D_CPU0_SB_DQ<13>")
	)
	(segment
		(start 332.326234 -230.525574)
		(end 332.121764 -230.525574)
		(width 0.088646)
		(layer "In11.Cu")
		(net "M_D_CPU0_SB_DQ<13>")
	)
	(segment
		(start 276.265894 -208.284826)
		(end 273.370294 -208.284826)
		(width 0.18288)
		(layer "In11.Cu")
		(net "M_D_CPU0_SB_DQ<13>")
	)
	(segment
		(start 336.287364 -230.584756)
		(end 336.272632 -230.57612)
		(width 0.088646)
		(layer "In11.Cu")
		(net "M_D_CPU0_SB_DQ<13>")
	)
	(segment
		(start 330.313538 -228.7143)
		(end 329.241404 -228.7143)
		(width 0.18288)
		(layer "In11.Cu")
		(net "M_D_CPU0_SB_DQ<13>")
	)
	(segment
		(start 346.89288 -233.34218)
		(end 347.205554 -233.34218)
		(width 0.088646)
		(layer "In11.Cu")
		(net "M_D_CPU0_SB_DQ<13>")
	)
	(segment
		(start 343.329768 -231.39527)
		(end 343.320878 -231.39019)
		(width 0.088646)
		(layer "In11.Cu")
		(net "M_D_CPU0_SB_DQ<13>")
	)
	(segment
		(start 311.849262 -209.414618)
		(end 309.804054 -208.840832)
		(width 0.18288)
		(layer "In11.Cu")
		(net "M_D_CPU0_SB_DQ<13>")
	)
	(segment
		(start 337.227164 -230.584756)
		(end 337.212432 -230.57612)
		(width 0.088646)
		(layer "In11.Cu")
		(net "M_D_CPU0_SB_DQ<13>")
	)
	(segment
		(start 303.835308 -207.99806)
		(end 303.327054 -207.489806)
		(width 0.18288)
		(layer "In11.Cu")
		(net "M_D_CPU0_SB_DQ<13>")
	)
	(segment
		(start 343.791032 -232.204006)
		(end 343.784936 -232.20045)
		(width 0.088646)
		(layer "In11.Cu")
		(net "M_D_CPU0_SB_DQ<13>")
	)
	(segment
		(start 345.766136 -233.017822)
		(end 345.755722 -233.023918)
		(width 0.088646)
		(layer "In11.Cu")
		(net "M_D_CPU0_SB_DQ<13>")
	)
	(segment
		(start 294.146986 -207.092804)
		(end 294.07866 -207.16113)
		(width 0.18288)
		(layer "In11.Cu")
		(net "M_D_CPU0_SB_DQ<13>")
	)
	(segment
		(start 342.860122 -230.5812)
		(end 342.851232 -230.57612)
		(width 0.088646)
		(layer "In11.Cu")
		(net "M_D_CPU0_SB_DQ<13>")
	)
	(segment
		(start 280.575766 -207.093312)
		(end 278.975312 -207.093312)
		(width 0.18288)
		(layer "In11.Cu")
		(net "M_D_CPU0_SB_DQ<13>")
	)
	(segment
		(start 334.407764 -230.584756)
		(end 334.393032 -230.57612)
		(width 0.088646)
		(layer "In11.Cu")
		(net "M_D_CPU0_SB_DQ<13>")
	)
	(segment
		(start 335.347564 -230.584756)
		(end 335.332832 -230.57612)
		(width 0.088646)
		(layer "In11.Cu")
		(net "M_D_CPU0_SB_DQ<13>")
	)
	(segment
		(start 330.65593 -228.7143)
		(end 330.313538 -228.7143)
		(width 0.088646)
		(layer "In11.Cu")
		(net "M_D_CPU0_SB_DQ<13>")
	)
	(segment
		(start 338.717382 -230.57612)
		(end 338.706968 -230.582216)
		(width 0.088646)
		(layer "In11.Cu")
		(net "M_D_CPU0_SB_DQ<13>")
	)
	(segment
		(start 296.244264 -207.092804)
		(end 294.146986 -207.092804)
		(width 0.18288)
		(layer "In11.Cu")
		(net "M_D_CPU0_SB_DQ<13>")
	)
	(segment
		(start 341.926164 -230.584756)
		(end 341.911432 -230.57612)
		(width 0.088646)
		(layer "In11.Cu")
		(net "M_D_CPU0_SB_DQ<13>")
	)
	(segment
		(start 306.205128 -207.99806)
		(end 303.835308 -207.99806)
		(width 0.18288)
		(layer "In11.Cu")
		(net "M_D_CPU0_SB_DQ<13>")
	)
	(segment
		(start 329.241404 -228.7143)
		(end 318.660272 -218.133168)
		(width 0.18288)
		(layer "In11.Cu")
		(net "M_D_CPU0_SB_DQ<13>")
	)
	(segment
		(start 270.585692 -214.569802)
		(end 270.241268 -214.914226)
		(width 0.18288)
		(layer "In11.Cu")
		(net "M_D_CPU0_SB_DQ<13>")
	)
	(segment
		(start 318.660272 -218.133168)
		(end 316.785752 -213.608158)
		(width 0.18288)
		(layer "In11.Cu")
		(net "M_D_CPU0_SB_DQ<13>")
	)
	(segment
		(start 333.467964 -230.584756)
		(end 333.453232 -230.57612)
		(width 0.088646)
		(layer "In11.Cu")
		(net "M_D_CPU0_SB_DQ<13>")
	)
	(segment
		(start 288.391346 -206.92872)
		(end 287.564576 -206.10195)
		(width 0.18288)
		(layer "In11.Cu")
		(net "M_D_CPU0_SB_DQ<13>")
	)
	(segment
		(start 278.975312 -207.093312)
		(end 278.164798 -207.903826)
		(width 0.18288)
		(layer "In11.Cu")
		(net "M_D_CPU0_SB_DQ<13>")
	)
	(segment
		(start 292.054788 -206.92872)
		(end 288.391346 -206.92872)
		(width 0.18288)
		(layer "In11.Cu")
		(net "M_D_CPU0_SB_DQ<13>")
	)
	(segment
		(start 265.156442 -214.739474)
		(end 264.729214 -215.166702)
		(width 0.18288)
		(layer "In11.Cu")
		(net "M_D_CPU0_SB_DQ<13>")
	)
	(segment
		(start 287.564576 -206.10195)
		(end 284.884622 -206.10195)
		(width 0.18288)
		(layer "In11.Cu")
		(net "M_D_CPU0_SB_DQ<13>")
	)
	(segment
		(start 343.978484 -232.543858)
		(end 343.978484 -232.528364)
		(width 0.088646)
		(layer "In11.Cu")
		(net "M_D_CPU0_SB_DQ<13>")
	)
	(segment
		(start 347.205554 -233.34218)
		(end 347.262958 -233.284776)
		(width 0.088646)
		(layer "In11.Cu")
		(net "M_D_CPU0_SB_DQ<13>")
	)
	(segment
		(start 344.826082 -233.017822)
		(end 344.81135 -233.026458)
		(width 0.088646)
		(layer "In11.Cu")
		(net "M_D_CPU0_SB_DQ<13>")
	)
	(segment
		(start 343.038684 -230.922576)
		(end 343.038684 -230.900478)
		(width 0.088646)
		(layer "In11.Cu")
		(net "M_D_CPU0_SB_DQ<13>")
	)
	(segment
		(start 346.150946 -233.023918)
		(end 346.140532 -233.017822)
		(width 0.088646)
		(layer "In11.Cu")
		(net "M_D_CPU0_SB_DQ<13>")
	)
	(segment
		(start 283.32049 -206.240126)
		(end 282.625546 -206.93507)
		(width 0.18288)
		(layer "In11.Cu")
		(net "M_D_CPU0_SB_DQ<13>")
	)
	(segment
		(start 316.785752 -213.608158)
		(end 314.42914 -211.251546)
		(width 0.18288)
		(layer "In11.Cu")
		(net "M_D_CPU0_SB_DQ<13>")
	)
	(segment
		(start 303.327054 -207.489806)
		(end 303.327054 -206.798164)
		(width 0.18288)
		(layer "In11.Cu")
		(net "M_D_CPU0_SB_DQ<13>")
	)
	(segment
		(start 309.804054 -208.840832)
		(end 307.0479 -208.840832)
		(width 0.18288)
		(layer "In11.Cu")
		(net "M_D_CPU0_SB_DQ<13>")
	)
	(segment
		(start 273.370294 -208.284826)
		(end 270.585692 -211.069428)
		(width 0.18288)
		(layer "In11.Cu")
		(net "M_D_CPU0_SB_DQ<13>")
	)
	(segment
		(start 298.376848 -206.23911)
		(end 297.659806 -206.956152)
		(width 0.18288)
		(layer "In11.Cu")
		(net "M_D_CPU0_SB_DQ<13>")
	)
	(segment
		(start 269.545562 -214.739474)
		(end 265.156442 -214.739474)
		(width 0.18288)
		(layer "In11.Cu")
		(net "M_D_CPU0_SB_DQ<13>")
	)
	(segment
		(start 297.659806 -206.956152)
		(end 296.380916 -206.956152)
		(width 0.18288)
		(layer "In11.Cu")
		(net "M_D_CPU0_SB_DQ<13>")
	)
	(segment
		(start 280.734008 -206.93507)
		(end 280.575766 -207.093312)
		(width 0.18288)
		(layer "In11.Cu")
		(net "M_D_CPU0_SB_DQ<13>")
	)
	(segment
		(start 340.986364 -230.584756)
		(end 340.971632 -230.57612)
		(width 0.088646)
		(layer "In11.Cu")
		(net "M_D_CPU0_SB_DQ<13>")
	)
	(segment
		(start 284.746446 -206.240126)
		(end 283.32049 -206.240126)
		(width 0.18288)
		(layer "In11.Cu")
		(net "M_D_CPU0_SB_DQ<13>")
	)
	(segment
		(start 331.112622 -229.516432)
		(end 331.112622 -229.170992)
		(width 0.088646)
		(layer "In11.Cu")
		(net "M_D_CPU0_SB_DQ<13>")
	)
	(segment
		(start 292.287198 -207.16113)
		(end 292.054788 -206.92872)
		(width 0.18288)
		(layer "In11.Cu")
		(net "M_D_CPU0_SB_DQ<13>")
	)
	(segment
		(start 331.112622 -229.170992)
		(end 330.65593 -228.7143)
		(width 0.088646)
		(layer "In11.Cu")
		(net "M_D_CPU0_SB_DQ<13>")
	)
	(segment
		(start 307.0479 -208.840832)
		(end 306.205128 -207.99806)
		(width 0.18288)
		(layer "In11.Cu")
		(net "M_D_CPU0_SB_DQ<13>")
	)
	(segment
		(start 278.164798 -207.903826)
		(end 277.291546 -207.903826)
		(width 0.18288)
		(layer "In11.Cu")
		(net "M_D_CPU0_SB_DQ<13>")
	)
	(segment
		(start 332.121764 -230.525574)
		(end 331.112622 -229.516432)
		(width 0.088646)
		(layer "In11.Cu")
		(net "M_D_CPU0_SB_DQ<13>")
	)
	(segment
		(start 302.768 -206.23911)
		(end 298.376848 -206.23911)
		(width 0.18288)
		(layer "In11.Cu")
		(net "M_D_CPU0_SB_DQ<13>")
	)
	(segment
		(start 277.291546 -207.903826)
		(end 276.265894 -208.284826)
		(width 0.18288)
		(layer "In11.Cu")
		(net "M_D_CPU0_SB_DQ<13>")
	)
	(segment
		(start 270.241268 -214.914226)
		(end 269.720314 -214.914226)
		(width 0.18288)
		(layer "In11.Cu")
		(net "M_D_CPU0_SB_DQ<13>")
	)
	(segment
		(start 332.528164 -230.584756)
		(end 332.513432 -230.57612)
		(width 0.088646)
		(layer "In11.Cu")
		(net "M_D_CPU0_SB_DQ<13>")
	)
	(segment
		(start 284.884622 -206.10195)
		(end 284.746446 -206.240126)
		(width 0.18288)
		(layer "In11.Cu")
		(net "M_D_CPU0_SB_DQ<13>")
	)
	(segment
		(start 314.42914 -211.251546)
		(end 313.68619 -211.251546)
		(width 0.18288)
		(layer "In11.Cu")
		(net "M_D_CPU0_SB_DQ<13>")
	)
	(segment
		(start 313.68619 -211.251546)
		(end 311.849262 -209.414618)
		(width 0.18288)
		(layer "In11.Cu")
		(net "M_D_CPU0_SB_DQ<13>")
	)
	(segment
		(start 347.088968 -233.022902)
		(end 347.080078 -233.017822)
		(width 0.088646)
		(layer "In11.Cu")
		(net "M_D_CPU0_SB_DQ<13>")
	)
	(segment
		(start 303.327054 -206.798164)
		(end 302.768 -206.23911)
		(width 0.18288)
		(layer "In11.Cu")
		(net "M_D_CPU0_SB_DQ<13>")
	)
	(segment
		(start 296.380916 -206.956152)
		(end 296.244264 -207.092804)
		(width 0.18288)
		(layer "In11.Cu")
		(net "M_D_CPU0_SB_DQ<13>")
	)
	(arc
		(start 344.260678 -233.017822)
		(mid 344.057855 -232.817591)
		(end 343.978484 -232.543858)
		(width 0.088646)
		(layer "In11.Cu")
		(net "M_D_CPU0_SB_DQ<13>")
	)
	(arc
		(start 335.332832 -230.57612)
		(mid 335.145634 -230.525977)
		(end 334.958436 -230.57612)
		(width 0.088646)
		(layer "In11.Cu")
		(net "M_D_CPU0_SB_DQ<13>")
	)
	(arc
		(start 339.091778 -230.57612)
		(mid 338.90458 -230.525977)
		(end 338.717382 -230.57612)
		(width 0.088646)
		(layer "In11.Cu")
		(net "M_D_CPU0_SB_DQ<13>")
	)
	(arc
		(start 333.453232 -230.57612)
		(mid 333.266034 -230.525977)
		(end 333.078836 -230.57612)
		(width 0.088646)
		(layer "In11.Cu")
		(net "M_D_CPU0_SB_DQ<13>")
	)
	(arc
		(start 338.152232 -230.57612)
		(mid 337.965034 -230.525977)
		(end 337.777836 -230.57612)
		(width 0.088646)
		(layer "In11.Cu")
		(net "M_D_CPU0_SB_DQ<13>")
	)
	(arc
		(start 338.706968 -230.582216)
		(mid 338.42879 -230.651939)
		(end 338.152232 -230.57612)
		(width 0.088646)
		(layer "In11.Cu")
		(net "M_D_CPU0_SB_DQ<13>")
	)
	(arc
		(start 334.393032 -230.57612)
		(mid 334.205834 -230.525977)
		(end 334.018636 -230.57612)
		(width 0.088646)
		(layer "In11.Cu")
		(net "M_D_CPU0_SB_DQ<13>")
	)
	(arc
		(start 335.898236 -230.57612)
		(mid 335.624037 -230.651955)
		(end 335.347564 -230.584756)
		(width 0.088646)
		(layer "In11.Cu")
		(net "M_D_CPU0_SB_DQ<13>")
	)
	(arc
		(start 334.958436 -230.57612)
		(mid 334.684237 -230.651955)
		(end 334.407764 -230.584756)
		(width 0.088646)
		(layer "In11.Cu")
		(net "M_D_CPU0_SB_DQ<13>")
	)
	(arc
		(start 337.212432 -230.57612)
		(mid 337.025234 -230.525977)
		(end 336.838036 -230.57612)
		(width 0.088646)
		(layer "In11.Cu")
		(net "M_D_CPU0_SB_DQ<13>")
	)
	(arc
		(start 346.705682 -233.017822)
		(mid 346.429123 -233.093565)
		(end 346.150946 -233.023918)
		(width 0.088646)
		(layer "In11.Cu")
		(net "M_D_CPU0_SB_DQ<13>")
	)
	(arc
		(start 344.81135 -233.026458)
		(mid 344.534875 -233.093778)
		(end 344.260678 -233.017822)
		(width 0.088646)
		(layer "In11.Cu")
		(net "M_D_CPU0_SB_DQ<13>")
	)
	(arc
		(start 340.031832 -230.57612)
		(mid 339.844634 -230.525977)
		(end 339.657436 -230.57612)
		(width 0.088646)
		(layer "In11.Cu")
		(net "M_D_CPU0_SB_DQ<13>")
	)
	(arc
		(start 343.784936 -232.20045)
		(mid 343.582349 -231.994099)
		(end 343.50833 -231.714548)
		(width 0.088646)
		(layer "In11.Cu")
		(net "M_D_CPU0_SB_DQ<13>")
	)
	(arc
		(start 340.597236 -230.57612)
		(mid 340.323037 -230.651955)
		(end 340.046564 -230.584756)
		(width 0.088646)
		(layer "In11.Cu")
		(net "M_D_CPU0_SB_DQ<13>")
	)
	(arc
		(start 343.320878 -231.39019)
		(mid 343.119596 -231.192703)
		(end 343.038684 -230.922576)
		(width 0.088646)
		(layer "In11.Cu")
		(net "M_D_CPU0_SB_DQ<13>")
	)
	(arc
		(start 339.657436 -230.57612)
		(mid 339.380623 -230.65199)
		(end 339.102192 -230.582216)
		(width 0.088646)
		(layer "In11.Cu")
		(net "M_D_CPU0_SB_DQ<13>")
	)
	(arc
		(start 347.262958 -233.284776)
		(mid 347.204802 -233.134663)
		(end 347.088968 -233.022902)
		(width 0.088646)
		(layer "In11.Cu")
		(net "M_D_CPU0_SB_DQ<13>")
	)
	(arc
		(start 343.50833 -231.714548)
		(mid 343.460651 -231.531648)
		(end 343.329768 -231.39527)
		(width 0.088646)
		(layer "In11.Cu")
		(net "M_D_CPU0_SB_DQ<13>")
	)
	(arc
		(start 343.038684 -230.900478)
		(mid 342.991005 -230.717578)
		(end 342.860122 -230.5812)
		(width 0.088646)
		(layer "In11.Cu")
		(net "M_D_CPU0_SB_DQ<13>")
	)
	(arc
		(start 336.838036 -230.57612)
		(mid 336.563837 -230.651955)
		(end 336.287364 -230.584756)
		(width 0.088646)
		(layer "In11.Cu")
		(net "M_D_CPU0_SB_DQ<13>")
	)
	(arc
		(start 333.078836 -230.57612)
		(mid 332.804637 -230.651955)
		(end 332.528164 -230.584756)
		(width 0.088646)
		(layer "In11.Cu")
		(net "M_D_CPU0_SB_DQ<13>")
	)
	(arc
		(start 341.911432 -230.57612)
		(mid 341.724234 -230.525977)
		(end 341.537036 -230.57612)
		(width 0.088646)
		(layer "In11.Cu")
		(net "M_D_CPU0_SB_DQ<13>")
	)
	(arc
		(start 347.080078 -233.017822)
		(mid 346.89288 -232.967679)
		(end 346.705682 -233.017822)
		(width 0.088646)
		(layer "In11.Cu")
		(net "M_D_CPU0_SB_DQ<13>")
	)
	(arc
		(start 343.978484 -232.528364)
		(mid 343.930805 -232.345464)
		(end 343.799922 -232.209086)
		(width 0.088646)
		(layer "In11.Cu")
		(net "M_D_CPU0_SB_DQ<13>")
	)
	(arc
		(start 340.971632 -230.57612)
		(mid 340.784434 -230.525977)
		(end 340.597236 -230.57612)
		(width 0.088646)
		(layer "In11.Cu")
		(net "M_D_CPU0_SB_DQ<13>")
	)
	(arc
		(start 345.200478 -233.017822)
		(mid 345.01328 -232.967679)
		(end 344.826082 -233.017822)
		(width 0.088646)
		(layer "In11.Cu")
		(net "M_D_CPU0_SB_DQ<13>")
	)
	(arc
		(start 341.537036 -230.57612)
		(mid 341.262837 -230.651955)
		(end 340.986364 -230.584756)
		(width 0.088646)
		(layer "In11.Cu")
		(net "M_D_CPU0_SB_DQ<13>")
	)
	(arc
		(start 336.272632 -230.57612)
		(mid 336.085434 -230.525977)
		(end 335.898236 -230.57612)
		(width 0.088646)
		(layer "In11.Cu")
		(net "M_D_CPU0_SB_DQ<13>")
	)
	(arc
		(start 342.476836 -230.57612)
		(mid 342.202637 -230.651955)
		(end 341.926164 -230.584756)
		(width 0.088646)
		(layer "In11.Cu")
		(net "M_D_CPU0_SB_DQ<13>")
	)
	(arc
		(start 334.018636 -230.57612)
		(mid 333.744437 -230.651955)
		(end 333.467964 -230.584756)
		(width 0.088646)
		(layer "In11.Cu")
		(net "M_D_CPU0_SB_DQ<13>")
	)
	(arc
		(start 342.851232 -230.57612)
		(mid 342.664034 -230.525977)
		(end 342.476836 -230.57612)
		(width 0.088646)
		(layer "In11.Cu")
		(net "M_D_CPU0_SB_DQ<13>")
	)
	(arc
		(start 337.777836 -230.57612)
		(mid 337.503637 -230.651955)
		(end 337.227164 -230.584756)
		(width 0.088646)
		(layer "In11.Cu")
		(net "M_D_CPU0_SB_DQ<13>")
	)
	(arc
		(start 332.513432 -230.57612)
		(mid 332.42316 -230.538521)
		(end 332.326234 -230.525574)
		(width 0.088646)
		(layer "In11.Cu")
		(net "M_D_CPU0_SB_DQ<13>")
	)
	(arc
		(start 346.140532 -233.017822)
		(mid 345.953334 -232.967679)
		(end 345.766136 -233.017822)
		(width 0.088646)
		(layer "In11.Cu")
		(net "M_D_CPU0_SB_DQ<13>")
	)
	(arc
		(start 345.755722 -233.023918)
		(mid 345.47729 -233.093764)
		(end 345.200478 -233.017822)
		(width 0.088646)
		(layer "In11.Cu")
		(net "M_D_CPU0_SB_DQ<13>")
	)
	(segment
		(start 258.28498 -216.932764)
		(end 258.11226 -217.105484)
		(width 0.20066)
		(layer "F.Cu")
		(net "M_D_CPU0_SB_DQ<12>")
	)
	(segment
		(start 257.414776 -216.866724)
		(end 256.080514 -216.866724)
		(width 0.20066)
		(layer "F.Cu")
		(net "M_D_CPU0_SB_DQ<12>")
	)
	(segment
		(start 259.056378 -216.433654)
		(end 258.49453 -216.433654)
		(width 0.20066)
		(layer "F.Cu")
		(net "M_D_CPU0_SB_DQ<12>")
	)
	(segment
		(start 257.653536 -217.105484)
		(end 257.414776 -216.866724)
		(width 0.20066)
		(layer "F.Cu")
		(net "M_D_CPU0_SB_DQ<12>")
	)
	(segment
		(start 264.729214 -216.866724)
		(end 263.624314 -216.866724)
		(width 0.20066)
		(layer "F.Cu")
		(net "M_D_CPU0_SB_DQ<12>")
	)
	(segment
		(start 263.624314 -216.866724)
		(end 262.255254 -216.866724)
		(width 0.20066)
		(layer "F.Cu")
		(net "M_D_CPU0_SB_DQ<12>")
	)
	(segment
		(start 346.42298 -234.69219)
		(end 346.423234 -234.691936)
		(width 0.20066)
		(layer "F.Cu")
		(net "M_D_CPU0_SB_DQ<12>")
	)
	(segment
		(start 346.423234 -234.691936)
		(end 346.423234 -234.15625)
		(width 0.20066)
		(layer "F.Cu")
		(net "M_D_CPU0_SB_DQ<12>")
	)
	(segment
		(start 259.31241 -216.441782)
		(end 259.064506 -216.441782)
		(width 0.101854)
		(layer "F.Cu")
		(net "M_D_CPU0_SB_DQ<12>")
	)
	(segment
		(start 258.11226 -217.105484)
		(end 257.653536 -217.105484)
		(width 0.20066)
		(layer "F.Cu")
		(net "M_D_CPU0_SB_DQ<12>")
	)
	(segment
		(start 258.49453 -216.433654)
		(end 258.28498 -216.643204)
		(width 0.20066)
		(layer "F.Cu")
		(net "M_D_CPU0_SB_DQ<12>")
	)
	(segment
		(start 258.28498 -216.643204)
		(end 258.28498 -216.932764)
		(width 0.20066)
		(layer "F.Cu")
		(net "M_D_CPU0_SB_DQ<12>")
	)
	(segment
		(start 261.381494 -216.441782)
		(end 259.31241 -216.441782)
		(width 0.1016)
		(layer "F.Cu")
		(net "M_D_CPU0_SB_DQ<12>")
	)
	(segment
		(start 261.830312 -216.441782)
		(end 261.381494 -216.441782)
		(width 0.20066)
		(layer "F.Cu")
		(net "M_D_CPU0_SB_DQ<12>")
	)
	(segment
		(start 259.064506 -216.441782)
		(end 259.056378 -216.433654)
		(width 0.101854)
		(layer "F.Cu")
		(net "M_D_CPU0_SB_DQ<12>")
	)
	(segment
		(start 262.255254 -216.866724)
		(end 261.830312 -216.441782)
		(width 0.20066)
		(layer "F.Cu")
		(net "M_D_CPU0_SB_DQ<12>")
	)
	(segment
		(start 269.637256 -216.441528)
		(end 268.453616 -216.441528)
		(width 0.18288)
		(layer "In11.Cu")
		(net "M_D_CPU0_SB_DQ<12>")
	)
	(segment
		(start 342.861392 -233.837988)
		(end 342.850978 -233.831892)
		(width 0.088646)
		(layer "In11.Cu")
		(net "M_D_CPU0_SB_DQ<12>")
	)
	(segment
		(start 302.699166 -209.419444)
		(end 301.219362 -207.93964)
		(width 0.18288)
		(layer "In11.Cu")
		(net "M_D_CPU0_SB_DQ<12>")
	)
	(segment
		(start 293.222426 -208.79308)
		(end 293.177976 -208.83753)
		(width 0.18288)
		(layer "In11.Cu")
		(net "M_D_CPU0_SB_DQ<12>")
	)
	(segment
		(start 307.203094 -210.367626)
		(end 307.074062 -210.496658)
		(width 0.18288)
		(layer "In11.Cu")
		(net "M_D_CPU0_SB_DQ<12>")
	)
	(segment
		(start 282.417774 -208.792318)
		(end 279.21966 -208.792318)
		(width 0.18288)
		(layer "In11.Cu")
		(net "M_D_CPU0_SB_DQ<12>")
	)
	(segment
		(start 312.613294 -212.247226)
		(end 310.682894 -212.247226)
		(width 0.18288)
		(layer "In11.Cu")
		(net "M_D_CPU0_SB_DQ<12>")
	)
	(segment
		(start 265.360912 -216.235026)
		(end 264.729214 -216.866724)
		(width 0.18288)
		(layer "In11.Cu")
		(net "M_D_CPU0_SB_DQ<12>")
	)
	(segment
		(start 343.805764 -233.840528)
		(end 343.791032 -233.831892)
		(width 0.088646)
		(layer "In11.Cu")
		(net "M_D_CPU0_SB_DQ<12>")
	)
	(segment
		(start 301.219362 -207.93964)
		(end 298.37634 -207.93964)
		(width 0.18288)
		(layer "In11.Cu")
		(net "M_D_CPU0_SB_DQ<12>")
	)
	(segment
		(start 315.999622 -214.555832)
		(end 314.351416 -212.907626)
		(width 0.18288)
		(layer "In11.Cu")
		(net "M_D_CPU0_SB_DQ<12>")
	)
	(segment
		(start 337.307682 -231.39019)
		(end 337.29295 -231.398826)
		(width 0.088646)
		(layer "In11.Cu")
		(net "M_D_CPU0_SB_DQ<12>")
	)
	(segment
		(start 276.96287 -209.642202)
		(end 276.843744 -209.523076)
		(width 0.18288)
		(layer "In11.Cu")
		(net "M_D_CPU0_SB_DQ<12>")
	)
	(segment
		(start 328.820272 -229.7303)
		(end 317.664084 -218.574112)
		(width 0.18288)
		(layer "In11.Cu")
		(net "M_D_CPU0_SB_DQ<12>")
	)
	(segment
		(start 340.127082 -231.39019)
		(end 340.11235 -231.398826)
		(width 0.088646)
		(layer "In11.Cu")
		(net "M_D_CPU0_SB_DQ<12>")
	)
	(segment
		(start 313.273694 -212.907626)
		(end 312.613294 -212.247226)
		(width 0.18288)
		(layer "In11.Cu")
		(net "M_D_CPU0_SB_DQ<12>")
	)
	(segment
		(start 341.920322 -232.209086)
		(end 341.911432 -232.204006)
		(width 0.088646)
		(layer "In11.Cu")
		(net "M_D_CPU0_SB_DQ<12>")
	)
	(segment
		(start 268.453616 -216.441528)
		(end 268.247114 -216.235026)
		(width 0.18288)
		(layer "In11.Cu")
		(net "M_D_CPU0_SB_DQ<12>")
	)
	(segment
		(start 342.098884 -232.543858)
		(end 342.098884 -232.528364)
		(width 0.088646)
		(layer "In11.Cu")
		(net "M_D_CPU0_SB_DQ<12>")
	)
	(segment
		(start 341.066882 -231.39019)
		(end 341.05215 -231.398826)
		(width 0.088646)
		(layer "In11.Cu")
		(net "M_D_CPU0_SB_DQ<12>")
	)
	(segment
		(start 274.037044 -209.523076)
		(end 272.80616 -210.75396)
		(width 0.18288)
		(layer "In11.Cu")
		(net "M_D_CPU0_SB_DQ<12>")
	)
	(segment
		(start 332.121764 -231.465882)
		(end 331.84973 -231.193848)
		(width 0.088646)
		(layer "In11.Cu")
		(net "M_D_CPU0_SB_DQ<12>")
	)
	(segment
		(start 331.84973 -230.988362)
		(end 330.591668 -229.7303)
		(width 0.088646)
		(layer "In11.Cu")
		(net "M_D_CPU0_SB_DQ<12>")
	)
	(segment
		(start 276.843744 -209.523076)
		(end 274.037044 -209.523076)
		(width 0.18288)
		(layer "In11.Cu")
		(net "M_D_CPU0_SB_DQ<12>")
	)
	(segment
		(start 331.84973 -231.193848)
		(end 331.84973 -230.988362)
		(width 0.088646)
		(layer "In11.Cu")
		(net "M_D_CPU0_SB_DQ<12>")
	)
	(segment
		(start 317.664084 -218.574112)
		(end 315.999622 -214.555832)
		(width 0.18288)
		(layer "In11.Cu")
		(net "M_D_CPU0_SB_DQ<12>")
	)
	(segment
		(start 304.330608 -209.419444)
		(end 302.699166 -209.419444)
		(width 0.18288)
		(layer "In11.Cu")
		(net "M_D_CPU0_SB_DQ<12>")
	)
	(segment
		(start 298.37634 -207.93964)
		(end 297.5229 -208.79308)
		(width 0.18288)
		(layer "In11.Cu")
		(net "M_D_CPU0_SB_DQ<12>")
	)
	(segment
		(start 314.351416 -212.907626)
		(end 313.273694 -212.907626)
		(width 0.18288)
		(layer "In11.Cu")
		(net "M_D_CPU0_SB_DQ<12>")
	)
	(segment
		(start 268.247114 -216.235026)
		(end 265.360912 -216.235026)
		(width 0.18288)
		(layer "In11.Cu")
		(net "M_D_CPU0_SB_DQ<12>")
	)
	(segment
		(start 297.5229 -208.79308)
		(end 293.222426 -208.79308)
		(width 0.18288)
		(layer "In11.Cu")
		(net "M_D_CPU0_SB_DQ<12>")
	)
	(segment
		(start 272.80616 -214.787226)
		(end 270.94434 -216.649046)
		(width 0.18288)
		(layer "In11.Cu")
		(net "M_D_CPU0_SB_DQ<12>")
	)
	(segment
		(start 279.21966 -208.792318)
		(end 278.369776 -209.642202)
		(width 0.18288)
		(layer "In11.Cu")
		(net "M_D_CPU0_SB_DQ<12>")
	)
	(segment
		(start 332.326234 -231.465882)
		(end 332.121764 -231.465882)
		(width 0.088646)
		(layer "In11.Cu")
		(net "M_D_CPU0_SB_DQ<12>")
	)
	(segment
		(start 338.247482 -231.39019)
		(end 338.23275 -231.398826)
		(width 0.088646)
		(layer "In11.Cu")
		(net "M_D_CPU0_SB_DQ<12>")
	)
	(segment
		(start 330.591668 -229.7303)
		(end 330.313538 -229.7303)
		(width 0.088646)
		(layer "In11.Cu")
		(net "M_D_CPU0_SB_DQ<12>")
	)
	(segment
		(start 342.389968 -233.022902)
		(end 342.381078 -233.017822)
		(width 0.088646)
		(layer "In11.Cu")
		(net "M_D_CPU0_SB_DQ<12>")
	)
	(segment
		(start 330.313538 -229.7303)
		(end 328.820272 -229.7303)
		(width 0.18288)
		(layer "In11.Cu")
		(net "M_D_CPU0_SB_DQ<12>")
	)
	(segment
		(start 310.682894 -212.247226)
		(end 308.803294 -210.367626)
		(width 0.18288)
		(layer "In11.Cu")
		(net "M_D_CPU0_SB_DQ<12>")
	)
	(segment
		(start 269.844774 -216.649046)
		(end 269.637256 -216.441528)
		(width 0.18288)
		(layer "In11.Cu")
		(net "M_D_CPU0_SB_DQ<12>")
	)
	(segment
		(start 293.177976 -208.83753)
		(end 287.062164 -208.83753)
		(width 0.18288)
		(layer "In11.Cu")
		(net "M_D_CPU0_SB_DQ<12>")
	)
	(segment
		(start 344.745564 -233.840528)
		(end 344.730832 -233.831892)
		(width 0.088646)
		(layer "In11.Cu")
		(net "M_D_CPU0_SB_DQ<12>")
	)
	(segment
		(start 305.407822 -210.496658)
		(end 304.330608 -209.419444)
		(width 0.18288)
		(layer "In11.Cu")
		(net "M_D_CPU0_SB_DQ<12>")
	)
	(segment
		(start 307.074062 -210.496658)
		(end 305.407822 -210.496658)
		(width 0.18288)
		(layer "In11.Cu")
		(net "M_D_CPU0_SB_DQ<12>")
	)
	(segment
		(start 336.367882 -231.39019)
		(end 336.357468 -231.396286)
		(width 0.088646)
		(layer "In11.Cu")
		(net "M_D_CPU0_SB_DQ<12>")
	)
	(segment
		(start 286.164274 -207.93964)
		(end 283.270452 -207.93964)
		(width 0.18288)
		(layer "In11.Cu")
		(net "M_D_CPU0_SB_DQ<12>")
	)
	(segment
		(start 287.062164 -208.83753)
		(end 286.164274 -207.93964)
		(width 0.18288)
		(layer "In11.Cu")
		(net "M_D_CPU0_SB_DQ<12>")
	)
	(segment
		(start 270.94434 -216.649046)
		(end 269.844774 -216.649046)
		(width 0.18288)
		(layer "In11.Cu")
		(net "M_D_CPU0_SB_DQ<12>")
	)
	(segment
		(start 341.450168 -231.39527)
		(end 341.441278 -231.39019)
		(width 0.088646)
		(layer "In11.Cu")
		(net "M_D_CPU0_SB_DQ<12>")
	)
	(segment
		(start 342.56853 -233.360722)
		(end 342.56853 -233.34218)
		(width 0.088646)
		(layer "In11.Cu")
		(net "M_D_CPU0_SB_DQ<12>")
	)
	(segment
		(start 308.803294 -210.367626)
		(end 307.203094 -210.367626)
		(width 0.18288)
		(layer "In11.Cu")
		(net "M_D_CPU0_SB_DQ<12>")
	)
	(segment
		(start 272.80616 -210.75396)
		(end 272.80616 -214.787226)
		(width 0.18288)
		(layer "In11.Cu")
		(net "M_D_CPU0_SB_DQ<12>")
	)
	(segment
		(start 283.270452 -207.93964)
		(end 282.417774 -208.792318)
		(width 0.18288)
		(layer "In11.Cu")
		(net "M_D_CPU0_SB_DQ<12>")
	)
	(segment
		(start 341.911432 -232.204006)
		(end 341.89924 -232.196894)
		(width 0.088646)
		(layer "In11.Cu")
		(net "M_D_CPU0_SB_DQ<12>")
	)
	(segment
		(start 278.369776 -209.642202)
		(end 276.96287 -209.642202)
		(width 0.18288)
		(layer "In11.Cu")
		(net "M_D_CPU0_SB_DQ<12>")
	)
	(arc
		(start 334.862932 -231.39019)
		(mid 334.675734 -231.340047)
		(end 334.488536 -231.39019)
		(width 0.088646)
		(layer "In11.Cu")
		(net "M_D_CPU0_SB_DQ<12>")
	)
	(arc
		(start 341.62873 -231.714548)
		(mid 341.581051 -231.531648)
		(end 341.450168 -231.39527)
		(width 0.088646)
		(layer "In11.Cu")
		(net "M_D_CPU0_SB_DQ<12>")
	)
	(arc
		(start 342.56853 -233.34218)
		(mid 342.520851 -233.15928)
		(end 342.389968 -233.022902)
		(width 0.088646)
		(layer "In11.Cu")
		(net "M_D_CPU0_SB_DQ<12>")
	)
	(arc
		(start 345.867736 -233.901234)
		(mid 345.765949 -233.875756)
		(end 345.670632 -233.831892)
		(width 0.088646)
		(layer "In11.Cu")
		(net "M_D_CPU0_SB_DQ<12>")
	)
	(arc
		(start 339.187282 -231.39019)
		(mid 338.90458 -231.465932)
		(end 338.621878 -231.39019)
		(width 0.088646)
		(layer "In11.Cu")
		(net "M_D_CPU0_SB_DQ<12>")
	)
	(arc
		(start 335.428336 -231.39019)
		(mid 335.145634 -231.465932)
		(end 334.862932 -231.39019)
		(width 0.088646)
		(layer "In11.Cu")
		(net "M_D_CPU0_SB_DQ<12>")
	)
	(arc
		(start 333.548736 -231.39019)
		(mid 333.266034 -231.465932)
		(end 332.983332 -231.39019)
		(width 0.088646)
		(layer "In11.Cu")
		(net "M_D_CPU0_SB_DQ<12>")
	)
	(arc
		(start 339.561678 -231.39019)
		(mid 339.37448 -231.340047)
		(end 339.187282 -231.39019)
		(width 0.088646)
		(layer "In11.Cu")
		(net "M_D_CPU0_SB_DQ<12>")
	)
	(arc
		(start 340.11235 -231.398826)
		(mid 339.835909 -231.465992)
		(end 339.561678 -231.39019)
		(width 0.088646)
		(layer "In11.Cu")
		(net "M_D_CPU0_SB_DQ<12>")
	)
	(arc
		(start 332.983332 -231.39019)
		(mid 332.796134 -231.340047)
		(end 332.608936 -231.39019)
		(width 0.088646)
		(layer "In11.Cu")
		(net "M_D_CPU0_SB_DQ<12>")
	)
	(arc
		(start 332.608936 -231.39019)
		(mid 332.47257 -231.446668)
		(end 332.326234 -231.465882)
		(width 0.088646)
		(layer "In11.Cu")
		(net "M_D_CPU0_SB_DQ<12>")
	)
	(arc
		(start 344.730832 -233.831892)
		(mid 344.543634 -233.781749)
		(end 344.356436 -233.831892)
		(width 0.088646)
		(layer "In11.Cu")
		(net "M_D_CPU0_SB_DQ<12>")
	)
	(arc
		(start 336.742278 -231.39019)
		(mid 336.55508 -231.340047)
		(end 336.367882 -231.39019)
		(width 0.088646)
		(layer "In11.Cu")
		(net "M_D_CPU0_SB_DQ<12>")
	)
	(arc
		(start 335.802732 -231.39019)
		(mid 335.615534 -231.340047)
		(end 335.428336 -231.39019)
		(width 0.088646)
		(layer "In11.Cu")
		(net "M_D_CPU0_SB_DQ<12>")
	)
	(arc
		(start 336.357468 -231.396286)
		(mid 336.07929 -231.465978)
		(end 335.802732 -231.39019)
		(width 0.088646)
		(layer "In11.Cu")
		(net "M_D_CPU0_SB_DQ<12>")
	)
	(arc
		(start 334.488536 -231.39019)
		(mid 334.205834 -231.465932)
		(end 333.923132 -231.39019)
		(width 0.088646)
		(layer "In11.Cu")
		(net "M_D_CPU0_SB_DQ<12>")
	)
	(arc
		(start 337.682078 -231.39019)
		(mid 337.49488 -231.340047)
		(end 337.307682 -231.39019)
		(width 0.088646)
		(layer "In11.Cu")
		(net "M_D_CPU0_SB_DQ<12>")
	)
	(arc
		(start 343.791032 -233.831892)
		(mid 343.603834 -233.781749)
		(end 343.416636 -233.831892)
		(width 0.088646)
		(layer "In11.Cu")
		(net "M_D_CPU0_SB_DQ<12>")
	)
	(arc
		(start 333.923132 -231.39019)
		(mid 333.735934 -231.340047)
		(end 333.548736 -231.39019)
		(width 0.088646)
		(layer "In11.Cu")
		(net "M_D_CPU0_SB_DQ<12>")
	)
	(arc
		(start 338.621878 -231.39019)
		(mid 338.43468 -231.340047)
		(end 338.247482 -231.39019)
		(width 0.088646)
		(layer "In11.Cu")
		(net "M_D_CPU0_SB_DQ<12>")
	)
	(arc
		(start 344.356436 -233.831892)
		(mid 344.082207 -233.907817)
		(end 343.805764 -233.840528)
		(width 0.088646)
		(layer "In11.Cu")
		(net "M_D_CPU0_SB_DQ<12>")
	)
	(arc
		(start 342.098884 -232.528364)
		(mid 342.051205 -232.345464)
		(end 341.920322 -232.209086)
		(width 0.088646)
		(layer "In11.Cu")
		(net "M_D_CPU0_SB_DQ<12>")
	)
	(arc
		(start 340.501478 -231.39019)
		(mid 340.31428 -231.340047)
		(end 340.127082 -231.39019)
		(width 0.088646)
		(layer "In11.Cu")
		(net "M_D_CPU0_SB_DQ<12>")
	)
	(arc
		(start 345.296236 -233.831892)
		(mid 345.022007 -233.907817)
		(end 344.745564 -233.840528)
		(width 0.088646)
		(layer "In11.Cu")
		(net "M_D_CPU0_SB_DQ<12>")
	)
	(arc
		(start 341.89924 -232.196894)
		(mid 341.701012 -231.991046)
		(end 341.62873 -231.714548)
		(width 0.088646)
		(layer "In11.Cu")
		(net "M_D_CPU0_SB_DQ<12>")
	)
	(arc
		(start 342.850978 -233.831892)
		(mid 342.648692 -233.632911)
		(end 342.56853 -233.360722)
		(width 0.088646)
		(layer "In11.Cu")
		(net "M_D_CPU0_SB_DQ<12>")
	)
	(arc
		(start 337.29295 -231.398826)
		(mid 337.016509 -231.465992)
		(end 336.742278 -231.39019)
		(width 0.088646)
		(layer "In11.Cu")
		(net "M_D_CPU0_SB_DQ<12>")
	)
	(arc
		(start 341.05215 -231.398826)
		(mid 340.775709 -231.465992)
		(end 340.501478 -231.39019)
		(width 0.088646)
		(layer "In11.Cu")
		(net "M_D_CPU0_SB_DQ<12>")
	)
	(arc
		(start 338.23275 -231.398826)
		(mid 337.956309 -231.465992)
		(end 337.682078 -231.39019)
		(width 0.088646)
		(layer "In11.Cu")
		(net "M_D_CPU0_SB_DQ<12>")
	)
	(arc
		(start 341.441278 -231.39019)
		(mid 341.25408 -231.340047)
		(end 341.066882 -231.39019)
		(width 0.088646)
		(layer "In11.Cu")
		(net "M_D_CPU0_SB_DQ<12>")
	)
	(arc
		(start 346.423234 -234.15625)
		(mid 346.16331 -233.989927)
		(end 345.867736 -233.901234)
		(width 0.088646)
		(layer "In11.Cu")
		(net "M_D_CPU0_SB_DQ<12>")
	)
	(arc
		(start 345.670632 -233.831892)
		(mid 345.483434 -233.781749)
		(end 345.296236 -233.831892)
		(width 0.088646)
		(layer "In11.Cu")
		(net "M_D_CPU0_SB_DQ<12>")
	)
	(arc
		(start 343.416636 -233.831892)
		(mid 343.139823 -233.907728)
		(end 342.861392 -233.837988)
		(width 0.088646)
		(layer "In11.Cu")
		(net "M_D_CPU0_SB_DQ<12>")
	)
	(arc
		(start 342.381078 -233.017822)
		(mid 342.178255 -232.817591)
		(end 342.098884 -232.543858)
		(width 0.088646)
		(layer "In11.Cu")
		(net "M_D_CPU0_SB_DQ<12>")
	)
	(segment
		(start 262.146288 -220.705934)
		(end 262.003794 -220.56344)
		(width 0.20066)
		(layer "F.Cu")
		(net "M_D_CPU0_SB_DQ<11>")
	)
	(segment
		(start 265.518646 -220.542612)
		(end 265.369548 -220.69171)
		(width 0.20066)
		(layer "F.Cu")
		(net "M_D_CPU0_SB_DQ<11>")
	)
	(segment
		(start 348.302834 -236.319568)
		(end 348.302834 -235.783882)
		(width 0.20066)
		(layer "F.Cu")
		(net "M_D_CPU0_SB_DQ<11>")
	)
	(segment
		(start 266.700762 -220.474286)
		(end 266.25423 -220.474286)
		(width 0.20066)
		(layer "F.Cu")
		(net "M_D_CPU0_SB_DQ<11>")
	)
	(segment
		(start 262.752332 -220.69171)
		(end 262.514334 -220.69171)
		(width 0.101854)
		(layer "F.Cu")
		(net "M_D_CPU0_SB_DQ<11>")
	)
	(segment
		(start 265.369548 -220.69171)
		(end 264.825226 -220.69171)
		(width 0.20066)
		(layer "F.Cu")
		(net "M_D_CPU0_SB_DQ<11>")
	)
	(segment
		(start 262.003794 -220.56344)
		(end 262.003794 -220.392752)
		(width 0.20066)
		(layer "F.Cu")
		(net "M_D_CPU0_SB_DQ<11>")
	)
	(segment
		(start 266.90828 -220.266768)
		(end 266.700762 -220.474286)
		(width 0.20066)
		(layer "F.Cu")
		(net "M_D_CPU0_SB_DQ<11>")
	)
	(segment
		(start 266.042394 -220.26245)
		(end 265.64717 -220.26245)
		(width 0.20066)
		(layer "F.Cu")
		(net "M_D_CPU0_SB_DQ<11>")
	)
	(segment
		(start 265.64717 -220.26245)
		(end 265.518646 -220.390974)
		(width 0.20066)
		(layer "F.Cu")
		(net "M_D_CPU0_SB_DQ<11>")
	)
	(segment
		(start 266.25423 -220.474286)
		(end 266.042394 -220.26245)
		(width 0.20066)
		(layer "F.Cu")
		(net "M_D_CPU0_SB_DQ<11>")
	)
	(segment
		(start 261.87781 -220.266768)
		(end 260.180582 -220.266768)
		(width 0.20066)
		(layer "F.Cu")
		(net "M_D_CPU0_SB_DQ<11>")
	)
	(segment
		(start 265.518646 -220.390974)
		(end 265.518646 -220.542612)
		(width 0.20066)
		(layer "F.Cu")
		(net "M_D_CPU0_SB_DQ<11>")
	)
	(segment
		(start 264.825226 -220.69171)
		(end 262.752332 -220.69171)
		(width 0.1016)
		(layer "F.Cu")
		(net "M_D_CPU0_SB_DQ<11>")
	)
	(segment
		(start 268.829282 -220.266768)
		(end 267.724382 -220.266768)
		(width 0.20066)
		(layer "F.Cu")
		(net "M_D_CPU0_SB_DQ<11>")
	)
	(segment
		(start 262.50011 -220.705934)
		(end 262.146288 -220.705934)
		(width 0.20066)
		(layer "F.Cu")
		(net "M_D_CPU0_SB_DQ<11>")
	)
	(segment
		(start 262.003794 -220.392752)
		(end 261.87781 -220.266768)
		(width 0.20066)
		(layer "F.Cu")
		(net "M_D_CPU0_SB_DQ<11>")
	)
	(segment
		(start 267.724382 -220.266768)
		(end 266.90828 -220.266768)
		(width 0.20066)
		(layer "F.Cu")
		(net "M_D_CPU0_SB_DQ<11>")
	)
	(segment
		(start 262.514334 -220.69171)
		(end 262.50011 -220.705934)
		(width 0.101854)
		(layer "F.Cu")
		(net "M_D_CPU0_SB_DQ<11>")
	)
	(segment
		(start 348.30258 -236.319822)
		(end 348.302834 -236.319568)
		(width 0.20066)
		(layer "F.Cu")
		(net "M_D_CPU0_SB_DQ<11>")
	)
	(segment
		(start 279.383998 -213.892384)
		(end 279.28824 -213.796626)
		(width 0.18288)
		(layer "In11.Cu")
		(net "M_D_CPU0_SB_DQ<11>")
	)
	(segment
		(start 286.77997 -213.165182)
		(end 286.58693 -212.972142)
		(width 0.18288)
		(layer "In11.Cu")
		(net "M_D_CPU0_SB_DQ<11>")
	)
	(segment
		(start 292.138354 -214.556086)
		(end 291.442902 -214.556086)
		(width 0.18288)
		(layer "In11.Cu")
		(net "M_D_CPU0_SB_DQ<11>")
	)
	(segment
		(start 300.795436 -212.637116)
		(end 300.795436 -212.997542)
		(width 0.18288)
		(layer "In11.Cu")
		(net "M_D_CPU0_SB_DQ<11>")
	)
	(segment
		(start 280.989024 -213.952582)
		(end 280.928826 -213.892384)
		(width 0.18288)
		(layer "In11.Cu")
		(net "M_D_CPU0_SB_DQ<11>")
	)
	(segment
		(start 300.988476 -212.444076)
		(end 300.795436 -212.637116)
		(width 0.18288)
		(layer "In11.Cu")
		(net "M_D_CPU0_SB_DQ<11>")
	)
	(segment
		(start 285.88589 -212.972142)
		(end 285.69285 -213.165182)
		(width 0.18288)
		(layer "In11.Cu")
		(net "M_D_CPU0_SB_DQ<11>")
	)
	(segment
		(start 304.155094 -214.050626)
		(end 303.29505 -213.190582)
		(width 0.18288)
		(layer "In11.Cu")
		(net "M_D_CPU0_SB_DQ<11>")
	)
	(segment
		(start 291.217096 -214.101426)
		(end 291.090096 -213.974426)
		(width 0.18288)
		(layer "In11.Cu")
		(net "M_D_CPU0_SB_DQ<11>")
	)
	(segment
		(start 343.805764 -236.099604)
		(end 343.791032 -236.10824)
		(width 0.088646)
		(layer "In11.Cu")
		(net "M_D_CPU0_SB_DQ<11>")
	)
	(segment
		(start 306.872894 -214.050626)
		(end 306.000912 -214.050626)
		(width 0.18288)
		(layer "In11.Cu")
		(net "M_D_CPU0_SB_DQ<11>")
	)
	(segment
		(start 339.102192 -236.102144)
		(end 339.091778 -236.10824)
		(width 0.088646)
		(layer "In11.Cu")
		(net "M_D_CPU0_SB_DQ<11>")
	)
	(segment
		(start 337.783932 -234.484164)
		(end 337.777836 -234.480608)
		(width 0.088646)
		(layer "In11.Cu")
		(net "M_D_CPU0_SB_DQ<11>")
	)
	(segment
		(start 293.947596 -213.892384)
		(end 292.972998 -214.866982)
		(width 0.18288)
		(layer "In11.Cu")
		(net "M_D_CPU0_SB_DQ<11>")
	)
	(segment
		(start 280.928826 -213.892384)
		(end 279.383998 -213.892384)
		(width 0.18288)
		(layer "In11.Cu")
		(net "M_D_CPU0_SB_DQ<11>")
	)
	(segment
		(start 315.43244 -219.039186)
		(end 314.080652 -217.687398)
		(width 0.18288)
		(layer "In11.Cu")
		(net "M_D_CPU0_SB_DQ<11>")
	)
	(segment
		(start 336.650584 -234.15625)
		(end 336.650584 -234.142026)
		(width 0.088646)
		(layer "In11.Cu")
		(net "M_D_CPU0_SB_DQ<11>")
	)
	(segment
		(start 289.83559 -213.781386)
		(end 289.64255 -213.974426)
		(width 0.18288)
		(layer "In11.Cu")
		(net "M_D_CPU0_SB_DQ<11>")
	)
	(segment
		(start 307.838094 -215.015826)
		(end 306.872894 -214.050626)
		(width 0.18288)
		(layer "In11.Cu")
		(net "M_D_CPU0_SB_DQ<11>")
	)
	(segment
		(start 300.602396 -213.190582)
		(end 299.81525 -213.190582)
		(width 0.18288)
		(layer "In11.Cu")
		(net "M_D_CPU0_SB_DQ<11>")
	)
	(segment
		(start 299.666914 -213.042246)
		(end 298.20743 -213.042246)
		(width 0.18288)
		(layer "In11.Cu")
		(net "M_D_CPU0_SB_DQ<11>")
	)
	(segment
		(start 300.795436 -212.997542)
		(end 300.602396 -213.190582)
		(width 0.18288)
		(layer "In11.Cu")
		(net "M_D_CPU0_SB_DQ<11>")
	)
	(segment
		(start 330.544932 -231.914446)
		(end 330.313538 -231.914446)
		(width 0.088646)
		(layer "In11.Cu")
		(net "M_D_CPU0_SB_DQ<11>")
	)
	(segment
		(start 305.106832 -213.857586)
		(end 304.913792 -214.050626)
		(width 0.18288)
		(layer "In11.Cu")
		(net "M_D_CPU0_SB_DQ<11>")
	)
	(segment
		(start 296.016426 -213.892384)
		(end 293.947596 -213.892384)
		(width 0.18288)
		(layer "In11.Cu")
		(net "M_D_CPU0_SB_DQ<11>")
	)
	(segment
		(start 306.000912 -214.050626)
		(end 305.807872 -213.857586)
		(width 0.18288)
		(layer "In11.Cu")
		(net "M_D_CPU0_SB_DQ<11>")
	)
	(segment
		(start 338.247736 -235.294424)
		(end 338.238846 -235.289344)
		(width 0.088646)
		(layer "In11.Cu")
		(net "M_D_CPU0_SB_DQ<11>")
	)
	(segment
		(start 290.53663 -213.456774)
		(end 290.34359 -213.263734)
		(width 0.18288)
		(layer "In11.Cu")
		(net "M_D_CPU0_SB_DQ<11>")
	)
	(segment
		(start 336.367882 -233.666538)
		(end 336.357468 -233.660442)
		(width 0.088646)
		(layer "In11.Cu")
		(net "M_D_CPU0_SB_DQ<11>")
	)
	(segment
		(start 286.58693 -212.715094)
		(end 286.39389 -212.522054)
		(width 0.18288)
		(layer "In11.Cu")
		(net "M_D_CPU0_SB_DQ<11>")
	)
	(segment
		(start 311.444894 -217.352626)
		(end 310.784494 -216.692226)
		(width 0.18288)
		(layer "In11.Cu")
		(net "M_D_CPU0_SB_DQ<11>")
	)
	(segment
		(start 284.774894 -213.165182)
		(end 284.651958 -213.042246)
		(width 0.18288)
		(layer "In11.Cu")
		(net "M_D_CPU0_SB_DQ<11>")
	)
	(segment
		(start 330.313538 -231.914446)
		(end 327.776586 -231.914446)
		(width 0.18288)
		(layer "In11.Cu")
		(net "M_D_CPU0_SB_DQ<11>")
	)
	(segment
		(start 289.64255 -213.974426)
		(end 288.864294 -213.974426)
		(width 0.18288)
		(layer "In11.Cu")
		(net "M_D_CPU0_SB_DQ<11>")
	)
	(segment
		(start 305.614832 -213.493604)
		(end 305.299872 -213.493604)
		(width 0.18288)
		(layer "In11.Cu")
		(net "M_D_CPU0_SB_DQ<11>")
	)
	(segment
		(start 288.05505 -213.165182)
		(end 286.77997 -213.165182)
		(width 0.18288)
		(layer "In11.Cu")
		(net "M_D_CPU0_SB_DQ<11>")
	)
	(segment
		(start 340.986364 -236.099604)
		(end 340.971632 -236.10824)
		(width 0.088646)
		(layer "In11.Cu")
		(net "M_D_CPU0_SB_DQ<11>")
	)
	(segment
		(start 332.326234 -233.590846)
		(end 331.613764 -233.590846)
		(width 0.088646)
		(layer "In11.Cu")
		(net "M_D_CPU0_SB_DQ<11>")
	)
	(segment
		(start 279.28824 -213.796626)
		(end 277.104094 -213.796626)
		(width 0.18288)
		(layer "In11.Cu")
		(net "M_D_CPU0_SB_DQ<11>")
	)
	(segment
		(start 288.864294 -213.974426)
		(end 288.05505 -213.165182)
		(width 0.18288)
		(layer "In11.Cu")
		(net "M_D_CPU0_SB_DQ<11>")
	)
	(segment
		(start 291.217096 -214.33028)
		(end 291.217096 -214.101426)
		(width 0.18288)
		(layer "In11.Cu")
		(net "M_D_CPU0_SB_DQ<11>")
	)
	(segment
		(start 310.784494 -216.692226)
		(end 310.022494 -216.692226)
		(width 0.18288)
		(layer "In11.Cu")
		(net "M_D_CPU0_SB_DQ<11>")
	)
	(segment
		(start 291.090096 -213.974426)
		(end 290.72967 -213.974426)
		(width 0.18288)
		(layer "In11.Cu")
		(net "M_D_CPU0_SB_DQ<11>")
	)
	(segment
		(start 308.346094 -215.015826)
		(end 307.838094 -215.015826)
		(width 0.18288)
		(layer "In11.Cu")
		(net "M_D_CPU0_SB_DQ<11>")
	)
	(segment
		(start 336.838036 -234.480608)
		(end 336.829146 -234.475528)
		(width 0.088646)
		(layer "In11.Cu")
		(net "M_D_CPU0_SB_DQ<11>")
	)
	(segment
		(start 305.807872 -213.857586)
		(end 305.807872 -213.686644)
		(width 0.18288)
		(layer "In11.Cu")
		(net "M_D_CPU0_SB_DQ<11>")
	)
	(segment
		(start 301.303436 -212.444076)
		(end 300.988476 -212.444076)
		(width 0.18288)
		(layer "In11.Cu")
		(net "M_D_CPU0_SB_DQ<11>")
	)
	(segment
		(start 312.310526 -217.352626)
		(end 311.444894 -217.352626)
		(width 0.18288)
		(layer "In11.Cu")
		(net "M_D_CPU0_SB_DQ<11>")
	)
	(segment
		(start 285.88589 -212.715094)
		(end 285.88589 -212.972142)
		(width 0.18288)
		(layer "In11.Cu")
		(net "M_D_CPU0_SB_DQ<11>")
	)
	(segment
		(start 301.496476 -212.637116)
		(end 301.303436 -212.444076)
		(width 0.18288)
		(layer "In11.Cu")
		(net "M_D_CPU0_SB_DQ<11>")
	)
	(segment
		(start 292.972998 -214.866982)
		(end 292.44925 -214.866982)
		(width 0.18288)
		(layer "In11.Cu")
		(net "M_D_CPU0_SB_DQ<11>")
	)
	(segment
		(start 301.496476 -212.997542)
		(end 301.496476 -212.637116)
		(width 0.18288)
		(layer "In11.Cu")
		(net "M_D_CPU0_SB_DQ<11>")
	)
	(segment
		(start 327.776586 -231.914446)
		(end 315.808106 -219.945966)
		(width 0.18288)
		(layer "In11.Cu")
		(net "M_D_CPU0_SB_DQ<11>")
	)
	(segment
		(start 315.808106 -219.945966)
		(end 315.43244 -219.039186)
		(width 0.18288)
		(layer "In11.Cu")
		(net "M_D_CPU0_SB_DQ<11>")
	)
	(segment
		(start 292.44925 -214.866982)
		(end 292.138354 -214.556086)
		(width 0.18288)
		(layer "In11.Cu")
		(net "M_D_CPU0_SB_DQ<11>")
	)
	(segment
		(start 344.741246 -236.102144)
		(end 344.730832 -236.10824)
		(width 0.088646)
		(layer "In11.Cu")
		(net "M_D_CPU0_SB_DQ<11>")
	)
	(segment
		(start 290.53663 -213.781386)
		(end 290.53663 -213.456774)
		(width 0.18288)
		(layer "In11.Cu")
		(net "M_D_CPU0_SB_DQ<11>")
	)
	(segment
		(start 314.080652 -217.687398)
		(end 312.645298 -217.687398)
		(width 0.18288)
		(layer "In11.Cu")
		(net "M_D_CPU0_SB_DQ<11>")
	)
	(segment
		(start 275.681694 -215.219026)
		(end 275.681694 -217.327734)
		(width 0.18288)
		(layer "In11.Cu")
		(net "M_D_CPU0_SB_DQ<11>")
	)
	(segment
		(start 284.651958 -213.042246)
		(end 282.99283 -213.042246)
		(width 0.18288)
		(layer "In11.Cu")
		(net "M_D_CPU0_SB_DQ<11>")
	)
	(segment
		(start 299.81525 -213.190582)
		(end 299.666914 -213.042246)
		(width 0.18288)
		(layer "In11.Cu")
		(net "M_D_CPU0_SB_DQ<11>")
	)
	(segment
		(start 310.022494 -216.692226)
		(end 308.346094 -215.015826)
		(width 0.18288)
		(layer "In11.Cu")
		(net "M_D_CPU0_SB_DQ<11>")
	)
	(segment
		(start 303.29505 -213.190582)
		(end 301.689516 -213.190582)
		(width 0.18288)
		(layer "In11.Cu")
		(net "M_D_CPU0_SB_DQ<11>")
	)
	(segment
		(start 269.417292 -220.854778)
		(end 268.829282 -220.266768)
		(width 0.18288)
		(layer "In11.Cu")
		(net "M_D_CPU0_SB_DQ<11>")
	)
	(segment
		(start 305.299872 -213.493604)
		(end 305.106832 -213.686644)
		(width 0.18288)
		(layer "In11.Cu")
		(net "M_D_CPU0_SB_DQ<11>")
	)
	(segment
		(start 347.892624 -235.613956)
		(end 347.690694 -235.412026)
		(width 0.088646)
		(layer "In11.Cu")
		(net "M_D_CPU0_SB_DQ<11>")
	)
	(segment
		(start 331.24648 -233.223562)
		(end 331.24648 -232.615994)
		(width 0.088646)
		(layer "In11.Cu")
		(net "M_D_CPU0_SB_DQ<11>")
	)
	(segment
		(start 289.83559 -213.456774)
		(end 289.83559 -213.781386)
		(width 0.18288)
		(layer "In11.Cu")
		(net "M_D_CPU0_SB_DQ<11>")
	)
	(segment
		(start 298.20743 -213.042246)
		(end 297.322494 -213.927182)
		(width 0.18288)
		(layer "In11.Cu")
		(net "M_D_CPU0_SB_DQ<11>")
	)
	(segment
		(start 290.34359 -213.263734)
		(end 290.02863 -213.263734)
		(width 0.18288)
		(layer "In11.Cu")
		(net "M_D_CPU0_SB_DQ<11>")
	)
	(segment
		(start 290.02863 -213.263734)
		(end 289.83559 -213.456774)
		(width 0.18288)
		(layer "In11.Cu")
		(net "M_D_CPU0_SB_DQ<11>")
	)
	(segment
		(start 305.106832 -213.686644)
		(end 305.106832 -213.857586)
		(width 0.18288)
		(layer "In11.Cu")
		(net "M_D_CPU0_SB_DQ<11>")
	)
	(segment
		(start 301.689516 -213.190582)
		(end 301.496476 -212.997542)
		(width 0.18288)
		(layer "In11.Cu")
		(net "M_D_CPU0_SB_DQ<11>")
	)
	(segment
		(start 304.913792 -214.050626)
		(end 304.155094 -214.050626)
		(width 0.18288)
		(layer "In11.Cu")
		(net "M_D_CPU0_SB_DQ<11>")
	)
	(segment
		(start 291.442902 -214.556086)
		(end 291.217096 -214.33028)
		(width 0.18288)
		(layer "In11.Cu")
		(net "M_D_CPU0_SB_DQ<11>")
	)
	(segment
		(start 331.613764 -233.590846)
		(end 331.24648 -233.223562)
		(width 0.088646)
		(layer "In11.Cu")
		(net "M_D_CPU0_SB_DQ<11>")
	)
	(segment
		(start 286.39389 -212.522054)
		(end 286.07893 -212.522054)
		(width 0.18288)
		(layer "In11.Cu")
		(net "M_D_CPU0_SB_DQ<11>")
	)
	(segment
		(start 282.99283 -213.042246)
		(end 282.082494 -213.952582)
		(width 0.18288)
		(layer "In11.Cu")
		(net "M_D_CPU0_SB_DQ<11>")
	)
	(segment
		(start 286.07893 -212.522054)
		(end 285.88589 -212.715094)
		(width 0.18288)
		(layer "In11.Cu")
		(net "M_D_CPU0_SB_DQ<11>")
	)
	(segment
		(start 342.865964 -236.099604)
		(end 342.851232 -236.10824)
		(width 0.088646)
		(layer "In11.Cu")
		(net "M_D_CPU0_SB_DQ<11>")
	)
	(segment
		(start 277.104094 -213.796626)
		(end 275.681694 -215.219026)
		(width 0.18288)
		(layer "In11.Cu")
		(net "M_D_CPU0_SB_DQ<11>")
	)
	(segment
		(start 338.530184 -235.792518)
		(end 338.530184 -235.773976)
		(width 0.088646)
		(layer "In11.Cu")
		(net "M_D_CPU0_SB_DQ<11>")
	)
	(segment
		(start 270.528542 -220.854778)
		(end 269.417292 -220.854778)
		(width 0.18288)
		(layer "In11.Cu")
		(net "M_D_CPU0_SB_DQ<11>")
	)
	(segment
		(start 312.645298 -217.687398)
		(end 312.310526 -217.352626)
		(width 0.18288)
		(layer "In11.Cu")
		(net "M_D_CPU0_SB_DQ<11>")
	)
	(segment
		(start 286.58693 -212.972142)
		(end 286.58693 -212.715094)
		(width 0.18288)
		(layer "In11.Cu")
		(net "M_D_CPU0_SB_DQ<11>")
	)
	(segment
		(start 347.182694 -235.412026)
		(end 347.055694 -235.539026)
		(width 0.088646)
		(layer "In11.Cu")
		(net "M_D_CPU0_SB_DQ<11>")
	)
	(segment
		(start 297.322494 -213.927182)
		(end 296.051224 -213.927182)
		(width 0.18288)
		(layer "In11.Cu")
		(net "M_D_CPU0_SB_DQ<11>")
	)
	(segment
		(start 274.371308 -218.63812)
		(end 271.595088 -219.788232)
		(width 0.18288)
		(layer "In11.Cu")
		(net "M_D_CPU0_SB_DQ<11>")
	)
	(segment
		(start 275.681694 -217.327734)
		(end 274.371308 -218.63812)
		(width 0.18288)
		(layer "In11.Cu")
		(net "M_D_CPU0_SB_DQ<11>")
	)
	(segment
		(start 290.72967 -213.974426)
		(end 290.53663 -213.781386)
		(width 0.18288)
		(layer "In11.Cu")
		(net "M_D_CPU0_SB_DQ<11>")
	)
	(segment
		(start 296.051224 -213.927182)
		(end 296.016426 -213.892384)
		(width 0.18288)
		(layer "In11.Cu")
		(net "M_D_CPU0_SB_DQ<11>")
	)
	(segment
		(start 331.24648 -232.615994)
		(end 330.544932 -231.914446)
		(width 0.088646)
		(layer "In11.Cu")
		(net "M_D_CPU0_SB_DQ<11>")
	)
	(segment
		(start 282.082494 -213.952582)
		(end 280.989024 -213.952582)
		(width 0.18288)
		(layer "In11.Cu")
		(net "M_D_CPU0_SB_DQ<11>")
	)
	(segment
		(start 337.227164 -234.471972)
		(end 337.212432 -234.480608)
		(width 0.088646)
		(layer "In11.Cu")
		(net "M_D_CPU0_SB_DQ<11>")
	)
	(segment
		(start 346.404946 -235.40974)
		(end 346.397072 -235.410248)
		(width 0.088646)
		(layer "In11.Cu")
		(net "M_D_CPU0_SB_DQ<11>")
	)
	(segment
		(start 285.69285 -213.165182)
		(end 284.774894 -213.165182)
		(width 0.18288)
		(layer "In11.Cu")
		(net "M_D_CPU0_SB_DQ<11>")
	)
	(segment
		(start 305.807872 -213.686644)
		(end 305.614832 -213.493604)
		(width 0.18288)
		(layer "In11.Cu")
		(net "M_D_CPU0_SB_DQ<11>")
	)
	(segment
		(start 340.046564 -236.099604)
		(end 340.031832 -236.10824)
		(width 0.088646)
		(layer "In11.Cu")
		(net "M_D_CPU0_SB_DQ<11>")
	)
	(segment
		(start 271.595088 -219.788232)
		(end 270.528542 -220.854778)
		(width 0.18288)
		(layer "In11.Cu")
		(net "M_D_CPU0_SB_DQ<11>")
	)
	(arc
		(start 342.476836 -236.10824)
		(mid 342.194134 -236.032498)
		(end 341.911432 -236.10824)
		(width 0.088646)
		(layer "In11.Cu")
		(net "M_D_CPU0_SB_DQ<11>")
	)
	(arc
		(start 340.597236 -236.10824)
		(mid 340.323007 -236.032315)
		(end 340.046564 -236.099604)
		(width 0.088646)
		(layer "In11.Cu")
		(net "M_D_CPU0_SB_DQ<11>")
	)
	(arc
		(start 337.777836 -234.480608)
		(mid 337.503637 -234.404773)
		(end 337.227164 -234.471972)
		(width 0.088646)
		(layer "In11.Cu")
		(net "M_D_CPU0_SB_DQ<11>")
	)
	(arc
		(start 332.608936 -233.666538)
		(mid 332.47257 -233.61006)
		(end 332.326234 -233.590846)
		(width 0.088646)
		(layer "In11.Cu")
		(net "M_D_CPU0_SB_DQ<11>")
	)
	(arc
		(start 343.791032 -236.10824)
		(mid 343.603834 -236.158383)
		(end 343.416636 -236.10824)
		(width 0.088646)
		(layer "In11.Cu")
		(net "M_D_CPU0_SB_DQ<11>")
	)
	(arc
		(start 333.923132 -233.666538)
		(mid 333.735934 -233.716681)
		(end 333.548736 -233.666538)
		(width 0.088646)
		(layer "In11.Cu")
		(net "M_D_CPU0_SB_DQ<11>")
	)
	(arc
		(start 345.295982 -236.10824)
		(mid 345.019423 -236.032531)
		(end 344.741246 -236.102144)
		(width 0.088646)
		(layer "In11.Cu")
		(net "M_D_CPU0_SB_DQ<11>")
	)
	(arc
		(start 345.670378 -236.10824)
		(mid 345.48318 -236.158383)
		(end 345.295982 -236.10824)
		(width 0.088646)
		(layer "In11.Cu")
		(net "M_D_CPU0_SB_DQ<11>")
	)
	(arc
		(start 337.212432 -234.480608)
		(mid 337.025234 -234.530751)
		(end 336.838036 -234.480608)
		(width 0.088646)
		(layer "In11.Cu")
		(net "M_D_CPU0_SB_DQ<11>")
	)
	(arc
		(start 346.397072 -235.410248)
		(mid 346.313739 -235.425695)
		(end 346.236036 -235.459524)
		(width 0.088646)
		(layer "In11.Cu")
		(net "M_D_CPU0_SB_DQ<11>")
	)
	(arc
		(start 344.730832 -236.10824)
		(mid 344.543634 -236.158383)
		(end 344.356436 -236.10824)
		(width 0.088646)
		(layer "In11.Cu")
		(net "M_D_CPU0_SB_DQ<11>")
	)
	(arc
		(start 346.062808 -235.639356)
		(mid 345.9081 -235.908535)
		(end 345.670378 -236.10824)
		(width 0.088646)
		(layer "In11.Cu")
		(net "M_D_CPU0_SB_DQ<11>")
	)
	(arc
		(start 340.031832 -236.10824)
		(mid 339.844634 -236.158383)
		(end 339.657436 -236.10824)
		(width 0.088646)
		(layer "In11.Cu")
		(net "M_D_CPU0_SB_DQ<11>")
	)
	(arc
		(start 347.690694 -235.412026)
		(mid 347.436694 -235.306816)
		(end 347.182694 -235.412026)
		(width 0.088646)
		(layer "In11.Cu")
		(net "M_D_CPU0_SB_DQ<11>")
	)
	(arc
		(start 340.971632 -236.10824)
		(mid 340.784434 -236.158383)
		(end 340.597236 -236.10824)
		(width 0.088646)
		(layer "In11.Cu")
		(net "M_D_CPU0_SB_DQ<11>")
	)
	(arc
		(start 341.537036 -236.10824)
		(mid 341.262807 -236.032315)
		(end 340.986364 -236.099604)
		(width 0.088646)
		(layer "In11.Cu")
		(net "M_D_CPU0_SB_DQ<11>")
	)
	(arc
		(start 339.657436 -236.10824)
		(mid 339.380623 -236.032404)
		(end 339.102192 -236.102144)
		(width 0.088646)
		(layer "In11.Cu")
		(net "M_D_CPU0_SB_DQ<11>")
	)
	(arc
		(start 346.236036 -235.459524)
		(mid 346.136708 -235.537194)
		(end 346.062808 -235.639356)
		(width 0.088646)
		(layer "In11.Cu")
		(net "M_D_CPU0_SB_DQ<11>")
	)
	(arc
		(start 335.802732 -233.666538)
		(mid 335.615534 -233.716681)
		(end 335.428336 -233.666538)
		(width 0.088646)
		(layer "In11.Cu")
		(net "M_D_CPU0_SB_DQ<11>")
	)
	(arc
		(start 336.357468 -233.660442)
		(mid 336.07929 -233.59075)
		(end 335.802732 -233.666538)
		(width 0.088646)
		(layer "In11.Cu")
		(net "M_D_CPU0_SB_DQ<11>")
	)
	(arc
		(start 339.091778 -236.10824)
		(mid 338.90458 -236.158383)
		(end 338.717382 -236.10824)
		(width 0.088646)
		(layer "In11.Cu")
		(net "M_D_CPU0_SB_DQ<11>")
	)
	(arc
		(start 343.416636 -236.10824)
		(mid 343.142407 -236.032315)
		(end 342.865964 -236.099604)
		(width 0.088646)
		(layer "In11.Cu")
		(net "M_D_CPU0_SB_DQ<11>")
	)
	(arc
		(start 333.548736 -233.666538)
		(mid 333.266034 -233.590796)
		(end 332.983332 -233.666538)
		(width 0.088646)
		(layer "In11.Cu")
		(net "M_D_CPU0_SB_DQ<11>")
	)
	(arc
		(start 336.650584 -234.142026)
		(mid 336.571365 -233.867341)
		(end 336.367882 -233.666538)
		(width 0.088646)
		(layer "In11.Cu")
		(net "M_D_CPU0_SB_DQ<11>")
	)
	(arc
		(start 338.717382 -236.10824)
		(mid 338.582449 -235.974886)
		(end 338.530184 -235.792518)
		(width 0.088646)
		(layer "In11.Cu")
		(net "M_D_CPU0_SB_DQ<11>")
	)
	(arc
		(start 334.862932 -233.666538)
		(mid 334.675734 -233.716681)
		(end 334.488536 -233.666538)
		(width 0.088646)
		(layer "In11.Cu")
		(net "M_D_CPU0_SB_DQ<11>")
	)
	(arc
		(start 342.851232 -236.10824)
		(mid 342.664034 -236.158383)
		(end 342.476836 -236.10824)
		(width 0.088646)
		(layer "In11.Cu")
		(net "M_D_CPU0_SB_DQ<11>")
	)
	(arc
		(start 338.060284 -234.970066)
		(mid 337.986368 -234.690564)
		(end 337.783932 -234.484164)
		(width 0.088646)
		(layer "In11.Cu")
		(net "M_D_CPU0_SB_DQ<11>")
	)
	(arc
		(start 332.983332 -233.666538)
		(mid 332.796134 -233.716681)
		(end 332.608936 -233.666538)
		(width 0.088646)
		(layer "In11.Cu")
		(net "M_D_CPU0_SB_DQ<11>")
	)
	(arc
		(start 348.302834 -235.783882)
		(mid 348.080826 -235.739722)
		(end 347.892624 -235.613956)
		(width 0.088646)
		(layer "In11.Cu")
		(net "M_D_CPU0_SB_DQ<11>")
	)
	(arc
		(start 341.911432 -236.10824)
		(mid 341.724234 -236.158383)
		(end 341.537036 -236.10824)
		(width 0.088646)
		(layer "In11.Cu")
		(net "M_D_CPU0_SB_DQ<11>")
	)
	(arc
		(start 334.488536 -233.666538)
		(mid 334.205834 -233.590796)
		(end 333.923132 -233.666538)
		(width 0.088646)
		(layer "In11.Cu")
		(net "M_D_CPU0_SB_DQ<11>")
	)
	(arc
		(start 336.829146 -234.475528)
		(mid 336.698232 -234.339168)
		(end 336.650584 -234.15625)
		(width 0.088646)
		(layer "In11.Cu")
		(net "M_D_CPU0_SB_DQ<11>")
	)
	(arc
		(start 346.750894 -235.539026)
		(mid 346.591948 -235.436879)
		(end 346.404946 -235.40974)
		(width 0.088646)
		(layer "In11.Cu")
		(net "M_D_CPU0_SB_DQ<11>")
	)
	(arc
		(start 338.530184 -235.773976)
		(mid 338.452073 -235.497027)
		(end 338.247736 -235.294424)
		(width 0.088646)
		(layer "In11.Cu")
		(net "M_D_CPU0_SB_DQ<11>")
	)
	(arc
		(start 347.055694 -235.539026)
		(mid 346.903294 -235.602152)
		(end 346.750894 -235.539026)
		(width 0.088646)
		(layer "In11.Cu")
		(net "M_D_CPU0_SB_DQ<11>")
	)
	(arc
		(start 338.238846 -235.289344)
		(mid 338.107932 -235.152984)
		(end 338.060284 -234.970066)
		(width 0.088646)
		(layer "In11.Cu")
		(net "M_D_CPU0_SB_DQ<11>")
	)
	(arc
		(start 344.356436 -236.10824)
		(mid 344.082207 -236.032315)
		(end 343.805764 -236.099604)
		(width 0.088646)
		(layer "In11.Cu")
		(net "M_D_CPU0_SB_DQ<11>")
	)
	(arc
		(start 335.428336 -233.666538)
		(mid 335.145634 -233.590796)
		(end 334.862932 -233.666538)
		(width 0.088646)
		(layer "In11.Cu")
		(net "M_D_CPU0_SB_DQ<11>")
	)
	(segment
		(start 266.409678 -221.96679)
		(end 266.197842 -222.178626)
		(width 0.20066)
		(layer "F.Cu")
		(net "M_D_CPU0_SB_DQ<10>")
	)
	(segment
		(start 268.829282 -221.96679)
		(end 267.724382 -221.96679)
		(width 0.20066)
		(layer "F.Cu")
		(net "M_D_CPU0_SB_DQ<10>")
	)
	(segment
		(start 267.724382 -221.96679)
		(end 266.409678 -221.96679)
		(width 0.20066)
		(layer "F.Cu")
		(net "M_D_CPU0_SB_DQ<10>")
	)
	(segment
		(start 265.601958 -222.01124)
		(end 265.601958 -221.685612)
		(width 0.20066)
		(layer "F.Cu")
		(net "M_D_CPU0_SB_DQ<10>")
	)
	(segment
		(start 266.197842 -222.178626)
		(end 265.769344 -222.178626)
		(width 0.20066)
		(layer "F.Cu")
		(net "M_D_CPU0_SB_DQ<10>")
	)
	(segment
		(start 347.832934 -237.133892)
		(end 347.83268 -237.133638)
		(width 0.20066)
		(layer "F.Cu")
		(net "M_D_CPU0_SB_DQ<10>")
	)
	(segment
		(start 262.50011 -221.531688)
		(end 261.762748 -221.531688)
		(width 0.20066)
		(layer "F.Cu")
		(net "M_D_CPU0_SB_DQ<10>")
	)
	(segment
		(start 347.83268 -237.133638)
		(end 347.83268 -236.597952)
		(width 0.20066)
		(layer "F.Cu")
		(net "M_D_CPU0_SB_DQ<10>")
	)
	(segment
		(start 262.51027 -221.541848)
		(end 262.50011 -221.531688)
		(width 0.101854)
		(layer "F.Cu")
		(net "M_D_CPU0_SB_DQ<10>")
	)
	(segment
		(start 265.458194 -221.541848)
		(end 264.825226 -221.541848)
		(width 0.20066)
		(layer "F.Cu")
		(net "M_D_CPU0_SB_DQ<10>")
	)
	(segment
		(start 262.765286 -221.541848)
		(end 262.51027 -221.541848)
		(width 0.101854)
		(layer "F.Cu")
		(net "M_D_CPU0_SB_DQ<10>")
	)
	(segment
		(start 261.762748 -221.531688)
		(end 261.327646 -221.96679)
		(width 0.20066)
		(layer "F.Cu")
		(net "M_D_CPU0_SB_DQ<10>")
	)
	(segment
		(start 265.769344 -222.178626)
		(end 265.601958 -222.01124)
		(width 0.20066)
		(layer "F.Cu")
		(net "M_D_CPU0_SB_DQ<10>")
	)
	(segment
		(start 261.327646 -221.96679)
		(end 260.180582 -221.96679)
		(width 0.20066)
		(layer "F.Cu")
		(net "M_D_CPU0_SB_DQ<10>")
	)
	(segment
		(start 264.825226 -221.541848)
		(end 262.765286 -221.541848)
		(width 0.1016)
		(layer "F.Cu")
		(net "M_D_CPU0_SB_DQ<10>")
	)
	(segment
		(start 265.601958 -221.685612)
		(end 265.458194 -221.541848)
		(width 0.20066)
		(layer "F.Cu")
		(net "M_D_CPU0_SB_DQ<10>")
	)
	(segment
		(start 297.898566 -215.063832)
		(end 297.583606 -215.063832)
		(width 0.18288)
		(layer "In11.Cu")
		(net "M_D_CPU0_SB_DQ<10>")
	)
	(segment
		(start 330.629514 -232.932478)
		(end 330.313538 -232.932478)
		(width 0.088646)
		(layer "In11.Cu")
		(net "M_D_CPU0_SB_DQ<10>")
	)
	(segment
		(start 341.066882 -236.922056)
		(end 341.05215 -236.91342)
		(width 0.088646)
		(layer "In11.Cu")
		(net "M_D_CPU0_SB_DQ<10>")
	)
	(segment
		(start 337.313778 -235.29798)
		(end 337.307682 -235.294424)
		(width 0.088646)
		(layer "In11.Cu")
		(net "M_D_CPU0_SB_DQ<10>")
	)
	(segment
		(start 330.313538 -232.932478)
		(end 327.23963 -232.932478)
		(width 0.18288)
		(layer "In11.Cu")
		(net "M_D_CPU0_SB_DQ<10>")
	)
	(segment
		(start 343.886282 -236.922056)
		(end 343.87155 -236.91342)
		(width 0.088646)
		(layer "In11.Cu")
		(net "M_D_CPU0_SB_DQ<10>")
	)
	(segment
		(start 332.528164 -234.471972)
		(end 332.513432 -234.480608)
		(width 0.088646)
		(layer "In11.Cu")
		(net "M_D_CPU0_SB_DQ<10>")
	)
	(segment
		(start 311.211468 -218.41206)
		(end 311.018428 -218.6051)
		(width 0.18288)
		(layer "In11.Cu")
		(net "M_D_CPU0_SB_DQ<10>")
	)
	(segment
		(start 294.574722 -216.441274)
		(end 294.381682 -216.248234)
		(width 0.18288)
		(layer "In11.Cu")
		(net "M_D_CPU0_SB_DQ<10>")
	)
	(segment
		(start 286.563308 -214.509858)
		(end 286.370268 -214.316818)
		(width 0.18288)
		(layer "In11.Cu")
		(net "M_D_CPU0_SB_DQ<10>")
	)
	(segment
		(start 346.625164 -236.099604)
		(end 346.610432 -236.10824)
		(width 0.088646)
		(layer "In11.Cu")
		(net "M_D_CPU0_SB_DQ<10>")
	)
	(segment
		(start 307.649118 -216.489026)
		(end 306.861718 -215.701626)
		(width 0.18288)
		(layer "In11.Cu")
		(net "M_D_CPU0_SB_DQ<10>")
	)
	(segment
		(start 274.360894 -220.603826)
		(end 273.479514 -220.603826)
		(width 0.18288)
		(layer "In11.Cu")
		(net "M_D_CPU0_SB_DQ<10>")
	)
	(segment
		(start 297.390566 -215.686386)
		(end 297.197526 -215.879426)
		(width 0.18288)
		(layer "In11.Cu")
		(net "M_D_CPU0_SB_DQ<10>")
	)
	(segment
		(start 334.407764 -234.471972)
		(end 334.393032 -234.480608)
		(width 0.088646)
		(layer "In11.Cu")
		(net "M_D_CPU0_SB_DQ<10>")
	)
	(segment
		(start 332.326234 -234.531154)
		(end 332.007464 -234.531154)
		(width 0.088646)
		(layer "In11.Cu")
		(net "M_D_CPU0_SB_DQ<10>")
	)
	(segment
		(start 285.862268 -214.509858)
		(end 285.862268 -215.181942)
		(width 0.18288)
		(layer "In11.Cu")
		(net "M_D_CPU0_SB_DQ<10>")
	)
	(segment
		(start 298.284646 -215.592152)
		(end 298.091606 -215.399112)
		(width 0.18288)
		(layer "In11.Cu")
		(net "M_D_CPU0_SB_DQ<10>")
	)
	(segment
		(start 327.23963 -232.932478)
		(end 314.301378 -219.994226)
		(width 0.18288)
		(layer "In11.Cu")
		(net "M_D_CPU0_SB_DQ<10>")
	)
	(segment
		(start 293.873682 -215.584024)
		(end 293.680642 -215.777064)
		(width 0.18288)
		(layer "In11.Cu")
		(net "M_D_CPU0_SB_DQ<10>")
	)
	(segment
		(start 295.20007 -216.441274)
		(end 294.574722 -216.441274)
		(width 0.18288)
		(layer "In11.Cu")
		(net "M_D_CPU0_SB_DQ<10>")
	)
	(segment
		(start 344.826082 -236.922056)
		(end 344.81135 -236.91342)
		(width 0.088646)
		(layer "In11.Cu")
		(net "M_D_CPU0_SB_DQ<10>")
	)
	(segment
		(start 285.054294 -215.374982)
		(end 284.837124 -215.592152)
		(width 0.18288)
		(layer "In11.Cu")
		(net "M_D_CPU0_SB_DQ<10>")
	)
	(segment
		(start 338.06003 -236.597952)
		(end 338.06003 -236.575854)
		(width 0.088646)
		(layer "In11.Cu")
		(net "M_D_CPU0_SB_DQ<10>")
	)
	(segment
		(start 277.853394 -218.609926)
		(end 276.202394 -218.609926)
		(width 0.18288)
		(layer "In11.Cu")
		(net "M_D_CPU0_SB_DQ<10>")
	)
	(segment
		(start 269.43685 -221.96679)
		(end 268.829282 -221.96679)
		(width 0.18288)
		(layer "In11.Cu")
		(net "M_D_CPU0_SB_DQ<10>")
	)
	(segment
		(start 298.091606 -215.399112)
		(end 298.091606 -215.256872)
		(width 0.18288)
		(layer "In11.Cu")
		(net "M_D_CPU0_SB_DQ<10>")
	)
	(segment
		(start 285.669228 -215.374982)
		(end 285.054294 -215.374982)
		(width 0.18288)
		(layer "In11.Cu")
		(net "M_D_CPU0_SB_DQ<10>")
	)
	(segment
		(start 342.006936 -236.922056)
		(end 341.996522 -236.91596)
		(width 0.088646)
		(layer "In11.Cu")
		(net "M_D_CPU0_SB_DQ<10>")
	)
	(segment
		(start 271.807432 -221.465648)
		(end 270.71828 -222.5548)
		(width 0.18288)
		(layer "In11.Cu")
		(net "M_D_CPU0_SB_DQ<10>")
	)
	(segment
		(start 300.907704 -215.13419)
		(end 300.714664 -215.32723)
		(width 0.18288)
		(layer "In11.Cu")
		(net "M_D_CPU0_SB_DQ<10>")
	)
	(segment
		(start 311.912508 -218.972638)
		(end 311.719468 -218.779598)
		(width 0.18288)
		(layer "In11.Cu")
		(net "M_D_CPU0_SB_DQ<10>")
	)
	(segment
		(start 300.714664 -215.32723)
		(end 300.03369 -215.32723)
		(width 0.18288)
		(layer "In11.Cu")
		(net "M_D_CPU0_SB_DQ<10>")
	)
	(segment
		(start 275.326094 -219.486226)
		(end 275.326094 -219.638626)
		(width 0.18288)
		(layer "In11.Cu")
		(net "M_D_CPU0_SB_DQ<10>")
	)
	(segment
		(start 293.680642 -216.295986)
		(end 293.487602 -216.489026)
		(width 0.18288)
		(layer "In11.Cu")
		(net "M_D_CPU0_SB_DQ<10>")
	)
	(segment
		(start 290.462716 -215.830404)
		(end 288.557716 -215.830404)
		(width 0.18288)
		(layer "In11.Cu")
		(net "M_D_CPU0_SB_DQ<10>")
	)
	(segment
		(start 280.253186 -216.44229)
		(end 278.509222 -216.44229)
		(width 0.18288)
		(layer "In11.Cu")
		(net "M_D_CPU0_SB_DQ<10>")
	)
	(segment
		(start 311.526428 -218.41206)
		(end 311.211468 -218.41206)
		(width 0.18288)
		(layer "In11.Cu")
		(net "M_D_CPU0_SB_DQ<10>")
	)
	(segment
		(start 345.765882 -236.92231)
		(end 345.765882 -236.922056)
		(width 0.088646)
		(layer "In11.Cu")
		(net "M_D_CPU0_SB_DQ<10>")
	)
	(segment
		(start 281.01925 -215.676226)
		(end 280.253186 -216.44229)
		(width 0.18288)
		(layer "In11.Cu")
		(net "M_D_CPU0_SB_DQ<10>")
	)
	(segment
		(start 310.825388 -218.972638)
		(end 310.423306 -218.972638)
		(width 0.18288)
		(layer "In11.Cu")
		(net "M_D_CPU0_SB_DQ<10>")
	)
	(segment
		(start 311.719468 -218.6051)
		(end 311.526428 -218.41206)
		(width 0.18288)
		(layer "In11.Cu")
		(net "M_D_CPU0_SB_DQ<10>")
	)
	(segment
		(start 347.253306 -236.152944)
		(end 347.175836 -236.10824)
		(width 0.088646)
		(layer "In11.Cu")
		(net "M_D_CPU0_SB_DQ<10>")
	)
	(segment
		(start 272.617692 -221.465648)
		(end 271.807432 -221.465648)
		(width 0.18288)
		(layer "In11.Cu")
		(net "M_D_CPU0_SB_DQ<10>")
	)
	(segment
		(start 330.760324 -233.284014)
		(end 330.760324 -233.063288)
		(width 0.088646)
		(layer "In11.Cu")
		(net "M_D_CPU0_SB_DQ<10>")
	)
	(segment
		(start 296.739564 -215.879426)
		(end 296.538142 -215.678004)
		(width 0.18288)
		(layer "In11.Cu")
		(net "M_D_CPU0_SB_DQ<10>")
	)
	(segment
		(start 339.187282 -236.922056)
		(end 339.17255 -236.91342)
		(width 0.088646)
		(layer "In11.Cu")
		(net "M_D_CPU0_SB_DQ<10>")
	)
	(segment
		(start 301.100744 -214.248238)
		(end 300.907704 -214.441278)
		(width 0.18288)
		(layer "In11.Cu")
		(net "M_D_CPU0_SB_DQ<10>")
	)
	(segment
		(start 307.939694 -216.489026)
		(end 307.649118 -216.489026)
		(width 0.18288)
		(layer "In11.Cu")
		(net "M_D_CPU0_SB_DQ<10>")
	)
	(segment
		(start 311.018428 -218.6051)
		(end 311.018428 -218.779598)
		(width 0.18288)
		(layer "In11.Cu")
		(net "M_D_CPU0_SB_DQ<10>")
	)
	(segment
		(start 332.007464 -234.531154)
		(end 330.760324 -233.284014)
		(width 0.088646)
		(layer "In11.Cu")
		(net "M_D_CPU0_SB_DQ<10>")
	)
	(segment
		(start 301.608744 -214.441278)
		(end 301.415704 -214.248238)
		(width 0.18288)
		(layer "In11.Cu")
		(net "M_D_CPU0_SB_DQ<10>")
	)
	(segment
		(start 283.373322 -215.592152)
		(end 283.289248 -215.676226)
		(width 0.18288)
		(layer "In11.Cu")
		(net "M_D_CPU0_SB_DQ<10>")
	)
	(segment
		(start 286.055308 -214.316818)
		(end 285.862268 -214.509858)
		(width 0.18288)
		(layer "In11.Cu")
		(net "M_D_CPU0_SB_DQ<10>")
	)
	(segment
		(start 313.183778 -219.994226)
		(end 312.16219 -218.972638)
		(width 0.18288)
		(layer "In11.Cu")
		(net "M_D_CPU0_SB_DQ<10>")
	)
	(segment
		(start 295.96334 -215.678004)
		(end 295.20007 -216.441274)
		(width 0.18288)
		(layer "In11.Cu")
		(net "M_D_CPU0_SB_DQ<10>")
	)
	(segment
		(start 294.381682 -216.248234)
		(end 294.381682 -215.777064)
		(width 0.18288)
		(layer "In11.Cu")
		(net "M_D_CPU0_SB_DQ<10>")
	)
	(segment
		(start 286.563308 -215.181942)
		(end 286.563308 -214.509858)
		(width 0.18288)
		(layer "In11.Cu")
		(net "M_D_CPU0_SB_DQ<10>")
	)
	(segment
		(start 294.188642 -215.584024)
		(end 293.873682 -215.584024)
		(width 0.18288)
		(layer "In11.Cu")
		(net "M_D_CPU0_SB_DQ<10>")
	)
	(segment
		(start 314.301378 -219.994226)
		(end 313.183778 -219.994226)
		(width 0.18288)
		(layer "In11.Cu")
		(net "M_D_CPU0_SB_DQ<10>")
	)
	(segment
		(start 297.583606 -215.063832)
		(end 297.390566 -215.256872)
		(width 0.18288)
		(layer "In11.Cu")
		(net "M_D_CPU0_SB_DQ<10>")
	)
	(segment
		(start 337.307682 -235.294424)
		(end 337.29295 -235.285788)
		(width 0.088646)
		(layer "In11.Cu")
		(net "M_D_CPU0_SB_DQ<10>")
	)
	(segment
		(start 303.924462 -215.47455)
		(end 301.801784 -215.47455)
		(width 0.18288)
		(layer "In11.Cu")
		(net "M_D_CPU0_SB_DQ<10>")
	)
	(segment
		(start 294.381682 -215.777064)
		(end 294.188642 -215.584024)
		(width 0.18288)
		(layer "In11.Cu")
		(net "M_D_CPU0_SB_DQ<10>")
	)
	(segment
		(start 311.018428 -218.779598)
		(end 310.825388 -218.972638)
		(width 0.18288)
		(layer "In11.Cu")
		(net "M_D_CPU0_SB_DQ<10>")
	)
	(segment
		(start 288.102294 -215.374982)
		(end 286.756348 -215.374982)
		(width 0.18288)
		(layer "In11.Cu")
		(net "M_D_CPU0_SB_DQ<10>")
	)
	(segment
		(start 273.479514 -220.603826)
		(end 272.617692 -221.465648)
		(width 0.18288)
		(layer "In11.Cu")
		(net "M_D_CPU0_SB_DQ<10>")
	)
	(segment
		(start 301.415704 -214.248238)
		(end 301.100744 -214.248238)
		(width 0.18288)
		(layer "In11.Cu")
		(net "M_D_CPU0_SB_DQ<10>")
	)
	(segment
		(start 286.756348 -215.374982)
		(end 286.563308 -215.181942)
		(width 0.18288)
		(layer "In11.Cu")
		(net "M_D_CPU0_SB_DQ<10>")
	)
	(segment
		(start 285.862268 -215.181942)
		(end 285.669228 -215.374982)
		(width 0.18288)
		(layer "In11.Cu")
		(net "M_D_CPU0_SB_DQ<10>")
	)
	(segment
		(start 297.390566 -215.256872)
		(end 297.390566 -215.686386)
		(width 0.18288)
		(layer "In11.Cu")
		(net "M_D_CPU0_SB_DQ<10>")
	)
	(segment
		(start 342.946482 -236.922056)
		(end 342.936068 -236.91596)
		(width 0.088646)
		(layer "In11.Cu")
		(net "M_D_CPU0_SB_DQ<10>")
	)
	(segment
		(start 338.247482 -236.922056)
		(end 338.233258 -236.913928)
		(width 0.088646)
		(layer "In11.Cu")
		(net "M_D_CPU0_SB_DQ<10>")
	)
	(segment
		(start 296.538142 -215.678004)
		(end 295.96334 -215.678004)
		(width 0.18288)
		(layer "In11.Cu")
		(net "M_D_CPU0_SB_DQ<10>")
	)
	(segment
		(start 284.837124 -215.592152)
		(end 283.373322 -215.592152)
		(width 0.18288)
		(layer "In11.Cu")
		(net "M_D_CPU0_SB_DQ<10>")
	)
	(segment
		(start 346.149168 -236.91723)
		(end 346.140278 -236.92231)
		(width 0.088646)
		(layer "In11.Cu")
		(net "M_D_CPU0_SB_DQ<10>")
	)
	(segment
		(start 306.861718 -215.701626)
		(end 304.151538 -215.701626)
		(width 0.18288)
		(layer "In11.Cu")
		(net "M_D_CPU0_SB_DQ<10>")
	)
	(segment
		(start 336.18043 -234.970066)
		(end 336.18043 -234.954572)
		(width 0.088646)
		(layer "In11.Cu")
		(net "M_D_CPU0_SB_DQ<10>")
	)
	(segment
		(start 283.289248 -215.676226)
		(end 281.01925 -215.676226)
		(width 0.18288)
		(layer "In11.Cu")
		(net "M_D_CPU0_SB_DQ<10>")
	)
	(segment
		(start 288.557716 -215.830404)
		(end 288.102294 -215.374982)
		(width 0.18288)
		(layer "In11.Cu")
		(net "M_D_CPU0_SB_DQ<10>")
	)
	(segment
		(start 291.84981 -216.248742)
		(end 290.881054 -216.248742)
		(width 0.18288)
		(layer "In11.Cu")
		(net "M_D_CPU0_SB_DQ<10>")
	)
	(segment
		(start 290.881054 -216.248742)
		(end 290.462716 -215.830404)
		(width 0.18288)
		(layer "In11.Cu")
		(net "M_D_CPU0_SB_DQ<10>")
	)
	(segment
		(start 346.32773 -236.583728)
		(end 346.32773 -236.597952)
		(width 0.088646)
		(layer "In11.Cu")
		(net "M_D_CPU0_SB_DQ<10>")
	)
	(segment
		(start 304.151538 -215.701626)
		(end 303.924462 -215.47455)
		(width 0.18288)
		(layer "In11.Cu")
		(net "M_D_CPU0_SB_DQ<10>")
	)
	(segment
		(start 301.608744 -215.28151)
		(end 301.608744 -214.441278)
		(width 0.18288)
		(layer "In11.Cu")
		(net "M_D_CPU0_SB_DQ<10>")
	)
	(segment
		(start 270.71828 -222.5548)
		(end 270.02486 -222.5548)
		(width 0.18288)
		(layer "In11.Cu")
		(net "M_D_CPU0_SB_DQ<10>")
	)
	(segment
		(start 300.907704 -214.441278)
		(end 300.907704 -215.13419)
		(width 0.18288)
		(layer "In11.Cu")
		(net "M_D_CPU0_SB_DQ<10>")
	)
	(segment
		(start 286.370268 -214.316818)
		(end 286.055308 -214.316818)
		(width 0.18288)
		(layer "In11.Cu")
		(net "M_D_CPU0_SB_DQ<10>")
	)
	(segment
		(start 300.03369 -215.32723)
		(end 299.768768 -215.592152)
		(width 0.18288)
		(layer "In11.Cu")
		(net "M_D_CPU0_SB_DQ<10>")
	)
	(segment
		(start 311.719468 -218.779598)
		(end 311.719468 -218.6051)
		(width 0.18288)
		(layer "In11.Cu")
		(net "M_D_CPU0_SB_DQ<10>")
	)
	(segment
		(start 278.120094 -218.343226)
		(end 277.853394 -218.609926)
		(width 0.18288)
		(layer "In11.Cu")
		(net "M_D_CPU0_SB_DQ<10>")
	)
	(segment
		(start 299.768768 -215.592152)
		(end 298.284646 -215.592152)
		(width 0.18288)
		(layer "In11.Cu")
		(net "M_D_CPU0_SB_DQ<10>")
	)
	(segment
		(start 270.02486 -222.5548)
		(end 269.43685 -221.96679)
		(width 0.18288)
		(layer "In11.Cu")
		(net "M_D_CPU0_SB_DQ<10>")
	)
	(segment
		(start 310.423306 -218.972638)
		(end 307.939694 -216.489026)
		(width 0.18288)
		(layer "In11.Cu")
		(net "M_D_CPU0_SB_DQ<10>")
	)
	(segment
		(start 345.765882 -236.922056)
		(end 345.75115 -236.91342)
		(width 0.088646)
		(layer "In11.Cu")
		(net "M_D_CPU0_SB_DQ<10>")
	)
	(segment
		(start 330.760324 -233.063288)
		(end 330.629514 -232.932478)
		(width 0.088646)
		(layer "In11.Cu")
		(net "M_D_CPU0_SB_DQ<10>")
	)
	(segment
		(start 297.197526 -215.879426)
		(end 296.739564 -215.879426)
		(width 0.18288)
		(layer "In11.Cu")
		(net "M_D_CPU0_SB_DQ<10>")
	)
	(segment
		(start 276.202394 -218.609926)
		(end 275.326094 -219.486226)
		(width 0.18288)
		(layer "In11.Cu")
		(net "M_D_CPU0_SB_DQ<10>")
	)
	(segment
		(start 278.509222 -216.44229)
		(end 278.120094 -216.831418)
		(width 0.18288)
		(layer "In11.Cu")
		(net "M_D_CPU0_SB_DQ<10>")
	)
	(segment
		(start 301.801784 -215.47455)
		(end 301.608744 -215.28151)
		(width 0.18288)
		(layer "In11.Cu")
		(net "M_D_CPU0_SB_DQ<10>")
	)
	(segment
		(start 298.091606 -215.256872)
		(end 297.898566 -215.063832)
		(width 0.18288)
		(layer "In11.Cu")
		(net "M_D_CPU0_SB_DQ<10>")
	)
	(segment
		(start 275.326094 -219.638626)
		(end 274.360894 -220.603826)
		(width 0.18288)
		(layer "In11.Cu")
		(net "M_D_CPU0_SB_DQ<10>")
	)
	(segment
		(start 293.487602 -216.489026)
		(end 292.090094 -216.489026)
		(width 0.18288)
		(layer "In11.Cu")
		(net "M_D_CPU0_SB_DQ<10>")
	)
	(segment
		(start 292.090094 -216.489026)
		(end 291.84981 -216.248742)
		(width 0.18288)
		(layer "In11.Cu")
		(net "M_D_CPU0_SB_DQ<10>")
	)
	(segment
		(start 335.347564 -234.471972)
		(end 335.332832 -234.480608)
		(width 0.088646)
		(layer "In11.Cu")
		(net "M_D_CPU0_SB_DQ<10>")
	)
	(segment
		(start 278.120094 -216.831418)
		(end 278.120094 -218.343226)
		(width 0.18288)
		(layer "In11.Cu")
		(net "M_D_CPU0_SB_DQ<10>")
	)
	(segment
		(start 337.777836 -236.10824)
		(end 337.768946 -236.10316)
		(width 0.088646)
		(layer "In11.Cu")
		(net "M_D_CPU0_SB_DQ<10>")
	)
	(segment
		(start 336.367882 -235.294424)
		(end 336.358992 -235.289344)
		(width 0.088646)
		(layer "In11.Cu")
		(net "M_D_CPU0_SB_DQ<10>")
	)
	(segment
		(start 333.467964 -234.471972)
		(end 333.453232 -234.480608)
		(width 0.088646)
		(layer "In11.Cu")
		(net "M_D_CPU0_SB_DQ<10>")
	)
	(segment
		(start 312.16219 -218.972638)
		(end 311.912508 -218.972638)
		(width 0.18288)
		(layer "In11.Cu")
		(net "M_D_CPU0_SB_DQ<10>")
	)
	(segment
		(start 293.680642 -215.777064)
		(end 293.680642 -216.295986)
		(width 0.18288)
		(layer "In11.Cu")
		(net "M_D_CPU0_SB_DQ<10>")
	)
	(arc
		(start 332.513432 -234.480608)
		(mid 332.42316 -234.518207)
		(end 332.326234 -234.531154)
		(width 0.088646)
		(layer "In11.Cu")
		(net "M_D_CPU0_SB_DQ<10>")
	)
	(arc
		(start 333.078836 -234.480608)
		(mid 332.804637 -234.404773)
		(end 332.528164 -234.471972)
		(width 0.088646)
		(layer "In11.Cu")
		(net "M_D_CPU0_SB_DQ<10>")
	)
	(arc
		(start 338.06003 -236.575854)
		(mid 337.979119 -236.305726)
		(end 337.777836 -236.10824)
		(width 0.088646)
		(layer "In11.Cu")
		(net "M_D_CPU0_SB_DQ<10>")
	)
	(arc
		(start 336.358992 -235.289344)
		(mid 336.228078 -235.152984)
		(end 336.18043 -234.970066)
		(width 0.088646)
		(layer "In11.Cu")
		(net "M_D_CPU0_SB_DQ<10>")
	)
	(arc
		(start 344.81135 -236.91342)
		(mid 344.534875 -236.8461)
		(end 344.260678 -236.922056)
		(width 0.088646)
		(layer "In11.Cu")
		(net "M_D_CPU0_SB_DQ<10>")
	)
	(arc
		(start 338.233258 -236.913928)
		(mid 338.106215 -236.778112)
		(end 338.06003 -236.597952)
		(width 0.088646)
		(layer "In11.Cu")
		(net "M_D_CPU0_SB_DQ<10>")
	)
	(arc
		(start 337.590384 -235.783882)
		(mid 337.516393 -235.504316)
		(end 337.313778 -235.29798)
		(width 0.088646)
		(layer "In11.Cu")
		(net "M_D_CPU0_SB_DQ<10>")
	)
	(arc
		(start 346.140278 -236.92231)
		(mid 345.95308 -236.972453)
		(end 345.765882 -236.92231)
		(width 0.088646)
		(layer "In11.Cu")
		(net "M_D_CPU0_SB_DQ<10>")
	)
	(arc
		(start 347.83268 -236.597952)
		(mid 347.557539 -236.35651)
		(end 347.253306 -236.152944)
		(width 0.088646)
		(layer "In11.Cu")
		(net "M_D_CPU0_SB_DQ<10>")
	)
	(arc
		(start 335.332832 -234.480608)
		(mid 335.145634 -234.530751)
		(end 334.958436 -234.480608)
		(width 0.088646)
		(layer "In11.Cu")
		(net "M_D_CPU0_SB_DQ<10>")
	)
	(arc
		(start 341.996522 -236.91596)
		(mid 341.71809 -236.846114)
		(end 341.441278 -236.922056)
		(width 0.088646)
		(layer "In11.Cu")
		(net "M_D_CPU0_SB_DQ<10>")
	)
	(arc
		(start 339.17255 -236.91342)
		(mid 338.896075 -236.8461)
		(end 338.621878 -236.922056)
		(width 0.088646)
		(layer "In11.Cu")
		(net "M_D_CPU0_SB_DQ<10>")
	)
	(arc
		(start 339.561678 -236.922056)
		(mid 339.37448 -236.972233)
		(end 339.187282 -236.922056)
		(width 0.088646)
		(layer "In11.Cu")
		(net "M_D_CPU0_SB_DQ<10>")
	)
	(arc
		(start 338.621878 -236.922056)
		(mid 338.43468 -236.972233)
		(end 338.247482 -236.922056)
		(width 0.088646)
		(layer "In11.Cu")
		(net "M_D_CPU0_SB_DQ<10>")
	)
	(arc
		(start 342.936068 -236.91596)
		(mid 342.65789 -236.846237)
		(end 342.381332 -236.922056)
		(width 0.088646)
		(layer "In11.Cu")
		(net "M_D_CPU0_SB_DQ<10>")
	)
	(arc
		(start 346.610432 -236.10824)
		(mid 346.406951 -236.309044)
		(end 346.32773 -236.583728)
		(width 0.088646)
		(layer "In11.Cu")
		(net "M_D_CPU0_SB_DQ<10>")
	)
	(arc
		(start 341.441278 -236.922056)
		(mid 341.25408 -236.972233)
		(end 341.066882 -236.922056)
		(width 0.088646)
		(layer "In11.Cu")
		(net "M_D_CPU0_SB_DQ<10>")
	)
	(arc
		(start 333.453232 -234.480608)
		(mid 333.266034 -234.530751)
		(end 333.078836 -234.480608)
		(width 0.088646)
		(layer "In11.Cu")
		(net "M_D_CPU0_SB_DQ<10>")
	)
	(arc
		(start 335.898236 -234.480608)
		(mid 335.624037 -234.404773)
		(end 335.347564 -234.471972)
		(width 0.088646)
		(layer "In11.Cu")
		(net "M_D_CPU0_SB_DQ<10>")
	)
	(arc
		(start 334.958436 -234.480608)
		(mid 334.684237 -234.404773)
		(end 334.407764 -234.471972)
		(width 0.088646)
		(layer "In11.Cu")
		(net "M_D_CPU0_SB_DQ<10>")
	)
	(arc
		(start 336.742278 -235.294424)
		(mid 336.55508 -235.344567)
		(end 336.367882 -235.294424)
		(width 0.088646)
		(layer "In11.Cu")
		(net "M_D_CPU0_SB_DQ<10>")
	)
	(arc
		(start 346.32773 -236.597952)
		(mid 346.280051 -236.780852)
		(end 346.149168 -236.91723)
		(width 0.088646)
		(layer "In11.Cu")
		(net "M_D_CPU0_SB_DQ<10>")
	)
	(arc
		(start 347.175836 -236.10824)
		(mid 346.901607 -236.032315)
		(end 346.625164 -236.099604)
		(width 0.088646)
		(layer "In11.Cu")
		(net "M_D_CPU0_SB_DQ<10>")
	)
	(arc
		(start 336.18043 -234.954572)
		(mid 336.10106 -234.680838)
		(end 335.898236 -234.480608)
		(width 0.088646)
		(layer "In11.Cu")
		(net "M_D_CPU0_SB_DQ<10>")
	)
	(arc
		(start 344.260678 -236.922056)
		(mid 344.07348 -236.972233)
		(end 343.886282 -236.922056)
		(width 0.088646)
		(layer "In11.Cu")
		(net "M_D_CPU0_SB_DQ<10>")
	)
	(arc
		(start 345.75115 -236.91342)
		(mid 345.474675 -236.8461)
		(end 345.200478 -236.922056)
		(width 0.088646)
		(layer "In11.Cu")
		(net "M_D_CPU0_SB_DQ<10>")
	)
	(arc
		(start 337.768946 -236.10316)
		(mid 337.638032 -235.9668)
		(end 337.590384 -235.783882)
		(width 0.088646)
		(layer "In11.Cu")
		(net "M_D_CPU0_SB_DQ<10>")
	)
	(arc
		(start 342.381332 -236.922056)
		(mid 342.194134 -236.972233)
		(end 342.006936 -236.922056)
		(width 0.088646)
		(layer "In11.Cu")
		(net "M_D_CPU0_SB_DQ<10>")
	)
	(arc
		(start 345.200478 -236.922056)
		(mid 345.01328 -236.972233)
		(end 344.826082 -236.922056)
		(width 0.088646)
		(layer "In11.Cu")
		(net "M_D_CPU0_SB_DQ<10>")
	)
	(arc
		(start 334.018636 -234.480608)
		(mid 333.744437 -234.404773)
		(end 333.467964 -234.471972)
		(width 0.088646)
		(layer "In11.Cu")
		(net "M_D_CPU0_SB_DQ<10>")
	)
	(arc
		(start 334.393032 -234.480608)
		(mid 334.205834 -234.530751)
		(end 334.018636 -234.480608)
		(width 0.088646)
		(layer "In11.Cu")
		(net "M_D_CPU0_SB_DQ<10>")
	)
	(arc
		(start 341.05215 -236.91342)
		(mid 340.775675 -236.8461)
		(end 340.501478 -236.922056)
		(width 0.088646)
		(layer "In11.Cu")
		(net "M_D_CPU0_SB_DQ<10>")
	)
	(arc
		(start 343.87155 -236.91342)
		(mid 343.595075 -236.8461)
		(end 343.320878 -236.922056)
		(width 0.088646)
		(layer "In11.Cu")
		(net "M_D_CPU0_SB_DQ<10>")
	)
	(arc
		(start 343.320878 -236.922056)
		(mid 343.13368 -236.972233)
		(end 342.946482 -236.922056)
		(width 0.088646)
		(layer "In11.Cu")
		(net "M_D_CPU0_SB_DQ<10>")
	)
	(arc
		(start 340.501478 -236.922056)
		(mid 340.31428 -236.972233)
		(end 340.127082 -236.922056)
		(width 0.088646)
		(layer "In11.Cu")
		(net "M_D_CPU0_SB_DQ<10>")
	)
	(arc
		(start 337.29295 -235.285788)
		(mid 337.016475 -235.218468)
		(end 336.742278 -235.294424)
		(width 0.088646)
		(layer "In11.Cu")
		(net "M_D_CPU0_SB_DQ<10>")
	)
	(arc
		(start 340.127082 -236.922056)
		(mid 339.84438 -236.84628)
		(end 339.561678 -236.922056)
		(width 0.088646)
		(layer "In11.Cu")
		(net "M_D_CPU0_SB_DQ<10>")
	)
	(segment
		(start 263.624314 -232.166668)
		(end 262.255254 -232.166668)
		(width 0.20066)
		(layer "F.Cu")
		(net "M_D_CPU0_SB_DQ<0>")
	)
	(segment
		(start 258.28498 -232.232708)
		(end 258.11226 -232.405428)
		(width 0.20066)
		(layer "F.Cu")
		(net "M_D_CPU0_SB_DQ<0>")
	)
	(segment
		(start 258.49453 -231.733598)
		(end 258.28498 -231.943148)
		(width 0.20066)
		(layer "F.Cu")
		(net "M_D_CPU0_SB_DQ<0>")
	)
	(segment
		(start 264.729214 -232.166668)
		(end 263.624314 -232.166668)
		(width 0.20066)
		(layer "F.Cu")
		(net "M_D_CPU0_SB_DQ<0>")
	)
	(segment
		(start 259.31241 -231.741726)
		(end 259.064506 -231.741726)
		(width 0.101854)
		(layer "F.Cu")
		(net "M_D_CPU0_SB_DQ<0>")
	)
	(segment
		(start 346.89288 -242.016788)
		(end 346.89288 -241.481102)
		(width 0.20066)
		(layer "F.Cu")
		(net "M_D_CPU0_SB_DQ<0>")
	)
	(segment
		(start 258.11226 -232.405428)
		(end 257.653536 -232.405428)
		(width 0.20066)
		(layer "F.Cu")
		(net "M_D_CPU0_SB_DQ<0>")
	)
	(segment
		(start 346.893134 -242.017042)
		(end 346.89288 -242.016788)
		(width 0.20066)
		(layer "F.Cu")
		(net "M_D_CPU0_SB_DQ<0>")
	)
	(segment
		(start 257.414776 -232.166668)
		(end 256.080514 -232.166668)
		(width 0.20066)
		(layer "F.Cu")
		(net "M_D_CPU0_SB_DQ<0>")
	)
	(segment
		(start 258.28498 -231.943148)
		(end 258.28498 -232.232708)
		(width 0.20066)
		(layer "F.Cu")
		(net "M_D_CPU0_SB_DQ<0>")
	)
	(segment
		(start 262.255254 -232.166668)
		(end 261.830312 -231.741726)
		(width 0.20066)
		(layer "F.Cu")
		(net "M_D_CPU0_SB_DQ<0>")
	)
	(segment
		(start 257.653536 -232.405428)
		(end 257.414776 -232.166668)
		(width 0.20066)
		(layer "F.Cu")
		(net "M_D_CPU0_SB_DQ<0>")
	)
	(segment
		(start 259.064506 -231.741726)
		(end 259.056378 -231.733598)
		(width 0.101854)
		(layer "F.Cu")
		(net "M_D_CPU0_SB_DQ<0>")
	)
	(segment
		(start 261.381494 -231.741726)
		(end 259.31241 -231.741726)
		(width 0.1016)
		(layer "F.Cu")
		(net "M_D_CPU0_SB_DQ<0>")
	)
	(segment
		(start 261.830312 -231.741726)
		(end 261.381494 -231.741726)
		(width 0.20066)
		(layer "F.Cu")
		(net "M_D_CPU0_SB_DQ<0>")
	)
	(segment
		(start 259.056378 -231.733598)
		(end 258.49453 -231.733598)
		(width 0.20066)
		(layer "F.Cu")
		(net "M_D_CPU0_SB_DQ<0>")
	)
	(segment
		(start 274.615402 -232.602278)
		(end 273.982688 -232.602278)
		(width 0.18288)
		(layer "In11.Cu")
		(net "M_D_CPU0_SB_DQ<0>")
	)
	(segment
		(start 265.370056 -231.525826)
		(end 264.729214 -232.166668)
		(width 0.18288)
		(layer "In11.Cu")
		(net "M_D_CPU0_SB_DQ<0>")
	)
	(segment
		(start 301.179484 -229.480364)
		(end 300.986444 -229.287324)
		(width 0.18288)
		(layer "In11.Cu")
		(net "M_D_CPU0_SB_DQ<0>")
	)
	(segment
		(start 294.964104 -230.04272)
		(end 294.962326 -230.040942)
		(width 0.18288)
		(layer "In11.Cu")
		(net "M_D_CPU0_SB_DQ<0>")
	)
	(segment
		(start 292.013894 -229.874826)
		(end 289.397694 -229.874826)
		(width 0.18288)
		(layer "In11.Cu")
		(net "M_D_CPU0_SB_DQ<0>")
	)
	(segment
		(start 269.104872 -231.745028)
		(end 267.275056 -231.745028)
		(width 0.18288)
		(layer "In11.Cu")
		(net "M_D_CPU0_SB_DQ<0>")
	)
	(segment
		(start 276.519894 -231.271826)
		(end 275.945854 -231.271826)
		(width 0.18288)
		(layer "In11.Cu")
		(net "M_D_CPU0_SB_DQ<0>")
	)
	(segment
		(start 284.94101 -228.604826)
		(end 284.354524 -229.191312)
		(width 0.18288)
		(layer "In11.Cu")
		(net "M_D_CPU0_SB_DQ<0>")
	)
	(segment
		(start 296.916094 -229.747826)
		(end 295.63568 -229.747826)
		(width 0.18288)
		(layer "In11.Cu")
		(net "M_D_CPU0_SB_DQ<0>")
	)
	(segment
		(start 267.055854 -231.525826)
		(end 265.370056 -231.525826)
		(width 0.18288)
		(layer "In11.Cu")
		(net "M_D_CPU0_SB_DQ<0>")
	)
	(segment
		(start 294.962326 -230.040942)
		(end 293.981378 -230.040942)
		(width 0.18288)
		(layer "In11.Cu")
		(net "M_D_CPU0_SB_DQ<0>")
	)
	(segment
		(start 300.986444 -228.823266)
		(end 300.793404 -228.630226)
		(width 0.18288)
		(layer "In11.Cu")
		(net "M_D_CPU0_SB_DQ<0>")
	)
	(segment
		(start 269.859252 -232.499408)
		(end 269.104872 -231.745028)
		(width 0.18288)
		(layer "In11.Cu")
		(net "M_D_CPU0_SB_DQ<0>")
	)
	(segment
		(start 308.671214 -230.738426)
		(end 307.45303 -230.738426)
		(width 0.18288)
		(layer "In11.Cu")
		(net "M_D_CPU0_SB_DQ<0>")
	)
	(segment
		(start 343.805764 -241.979196)
		(end 343.791032 -241.97056)
		(width 0.088646)
		(layer "In11.Cu")
		(net "M_D_CPU0_SB_DQ<0>")
	)
	(segment
		(start 310.2737 -231.744012)
		(end 309.6768 -231.744012)
		(width 0.18288)
		(layer "In11.Cu")
		(net "M_D_CPU0_SB_DQ<0>")
	)
	(segment
		(start 282.006294 -229.798626)
		(end 280.49728 -229.798626)
		(width 0.18288)
		(layer "In11.Cu")
		(net "M_D_CPU0_SB_DQ<0>")
	)
	(segment
		(start 292.420294 -230.281226)
		(end 292.013894 -229.874826)
		(width 0.18288)
		(layer "In11.Cu")
		(net "M_D_CPU0_SB_DQ<0>")
	)
	(segment
		(start 331.171042 -239.460786)
		(end 330.351384 -239.460786)
		(width 0.088646)
		(layer "In11.Cu")
		(net "M_D_CPU0_SB_DQ<0>")
	)
	(segment
		(start 334.871822 -241.161824)
		(end 334.862932 -241.156744)
		(width 0.088646)
		(layer "In11.Cu")
		(net "M_D_CPU0_SB_DQ<0>")
	)
	(segment
		(start 282.613608 -229.191312)
		(end 282.006294 -229.798626)
		(width 0.18288)
		(layer "In11.Cu")
		(net "M_D_CPU0_SB_DQ<0>")
	)
	(segment
		(start 278.297894 -230.509826)
		(end 277.281894 -230.509826)
		(width 0.18288)
		(layer "In11.Cu")
		(net "M_D_CPU0_SB_DQ<0>")
	)
	(segment
		(start 301.687484 -229.287324)
		(end 301.494444 -229.480364)
		(width 0.18288)
		(layer "In11.Cu")
		(net "M_D_CPU0_SB_DQ<0>")
	)
	(segment
		(start 297.471338 -229.192582)
		(end 296.916094 -229.747826)
		(width 0.18288)
		(layer "In11.Cu")
		(net "M_D_CPU0_SB_DQ<0>")
	)
	(segment
		(start 306.74183 -230.027226)
		(end 304.790094 -230.027226)
		(width 0.18288)
		(layer "In11.Cu")
		(net "M_D_CPU0_SB_DQ<0>")
	)
	(segment
		(start 310.466486 -231.551226)
		(end 310.2737 -231.744012)
		(width 0.18288)
		(layer "In11.Cu")
		(net "M_D_CPU0_SB_DQ<0>")
	)
	(segment
		(start 333.462122 -240.348008)
		(end 333.453232 -240.342928)
		(width 0.088646)
		(layer "In11.Cu")
		(net "M_D_CPU0_SB_DQ<0>")
	)
	(segment
		(start 277.281894 -230.509826)
		(end 276.519894 -231.271826)
		(width 0.18288)
		(layer "In11.Cu")
		(net "M_D_CPU0_SB_DQ<0>")
	)
	(segment
		(start 279.762966 -230.042466)
		(end 279.762712 -230.04272)
		(width 0.18288)
		(layer "In11.Cu")
		(net "M_D_CPU0_SB_DQ<0>")
	)
	(segment
		(start 267.275056 -231.745028)
		(end 267.055854 -231.525826)
		(width 0.18288)
		(layer "In11.Cu")
		(net "M_D_CPU0_SB_DQ<0>")
	)
	(segment
		(start 273.879818 -232.499408)
		(end 269.859252 -232.499408)
		(width 0.18288)
		(layer "In11.Cu")
		(net "M_D_CPU0_SB_DQ<0>")
	)
	(segment
		(start 301.880524 -228.630226)
		(end 301.687484 -228.823266)
		(width 0.18288)
		(layer "In11.Cu")
		(net "M_D_CPU0_SB_DQ<0>")
	)
	(segment
		(start 342.865964 -241.979196)
		(end 342.851232 -241.97056)
		(width 0.088646)
		(layer "In11.Cu")
		(net "M_D_CPU0_SB_DQ<0>")
	)
	(segment
		(start 279.762712 -230.04272)
		(end 278.765 -230.04272)
		(width 0.18288)
		(layer "In11.Cu")
		(net "M_D_CPU0_SB_DQ<0>")
	)
	(segment
		(start 300.793404 -228.630226)
		(end 300.333918 -228.630226)
		(width 0.18288)
		(layer "In11.Cu")
		(net "M_D_CPU0_SB_DQ<0>")
	)
	(segment
		(start 301.494444 -229.480364)
		(end 301.179484 -229.480364)
		(width 0.18288)
		(layer "In11.Cu")
		(net "M_D_CPU0_SB_DQ<0>")
	)
	(segment
		(start 299.771562 -229.192582)
		(end 297.471338 -229.192582)
		(width 0.18288)
		(layer "In11.Cu")
		(net "M_D_CPU0_SB_DQ<0>")
	)
	(segment
		(start 344.745564 -241.979196)
		(end 344.730832 -241.97056)
		(width 0.088646)
		(layer "In11.Cu")
		(net "M_D_CPU0_SB_DQ<0>")
	)
	(segment
		(start 303.393094 -228.630226)
		(end 301.880524 -228.630226)
		(width 0.18288)
		(layer "In11.Cu")
		(net "M_D_CPU0_SB_DQ<0>")
	)
	(segment
		(start 336.272632 -241.97056)
		(end 336.26425 -241.965734)
		(width 0.088646)
		(layer "In11.Cu")
		(net "M_D_CPU0_SB_DQ<0>")
	)
	(segment
		(start 336.287364 -241.979196)
		(end 336.272632 -241.97056)
		(width 0.088646)
		(layer "In11.Cu")
		(net "M_D_CPU0_SB_DQ<0>")
	)
	(segment
		(start 315.250068 -233.214926)
		(end 313.971686 -233.214926)
		(width 0.18288)
		(layer "In11.Cu")
		(net "M_D_CPU0_SB_DQ<0>")
	)
	(segment
		(start 332.528164 -240.351564)
		(end 332.513432 -240.342928)
		(width 0.088646)
		(layer "In11.Cu")
		(net "M_D_CPU0_SB_DQ<0>")
	)
	(segment
		(start 340.986364 -241.979196)
		(end 340.971632 -241.97056)
		(width 0.088646)
		(layer "In11.Cu")
		(net "M_D_CPU0_SB_DQ<0>")
	)
	(segment
		(start 321.495928 -239.460786)
		(end 315.250068 -233.214926)
		(width 0.18288)
		(layer "In11.Cu")
		(net "M_D_CPU0_SB_DQ<0>")
	)
	(segment
		(start 279.87244 -230.04272)
		(end 279.872186 -230.042466)
		(width 0.18288)
		(layer "In11.Cu")
		(net "M_D_CPU0_SB_DQ<0>")
	)
	(segment
		(start 340.046564 -241.979196)
		(end 340.031832 -241.97056)
		(width 0.088646)
		(layer "In11.Cu")
		(net "M_D_CPU0_SB_DQ<0>")
	)
	(segment
		(start 332.002384 -240.292128)
		(end 331.171042 -239.460786)
		(width 0.088646)
		(layer "In11.Cu")
		(net "M_D_CPU0_SB_DQ<0>")
	)
	(segment
		(start 293.741094 -230.281226)
		(end 292.420294 -230.281226)
		(width 0.18288)
		(layer "In11.Cu")
		(net "M_D_CPU0_SB_DQ<0>")
	)
	(segment
		(start 330.351384 -239.460786)
		(end 321.495928 -239.460786)
		(width 0.18288)
		(layer "In11.Cu")
		(net "M_D_CPU0_SB_DQ<0>")
	)
	(segment
		(start 288.127694 -228.604826)
		(end 284.94101 -228.604826)
		(width 0.18288)
		(layer "In11.Cu")
		(net "M_D_CPU0_SB_DQ<0>")
	)
	(segment
		(start 307.45303 -230.738426)
		(end 306.74183 -230.027226)
		(width 0.18288)
		(layer "In11.Cu")
		(net "M_D_CPU0_SB_DQ<0>")
	)
	(segment
		(start 293.981378 -230.040942)
		(end 293.741094 -230.281226)
		(width 0.18288)
		(layer "In11.Cu")
		(net "M_D_CPU0_SB_DQ<0>")
	)
	(segment
		(start 278.765 -230.04272)
		(end 278.297894 -230.509826)
		(width 0.18288)
		(layer "In11.Cu")
		(net "M_D_CPU0_SB_DQ<0>")
	)
	(segment
		(start 300.333918 -228.630226)
		(end 299.771562 -229.192582)
		(width 0.18288)
		(layer "In11.Cu")
		(net "M_D_CPU0_SB_DQ<0>")
	)
	(segment
		(start 313.971686 -233.214926)
		(end 312.307986 -231.551226)
		(width 0.18288)
		(layer "In11.Cu")
		(net "M_D_CPU0_SB_DQ<0>")
	)
	(segment
		(start 295.63568 -229.747826)
		(end 295.340786 -230.04272)
		(width 0.18288)
		(layer "In11.Cu")
		(net "M_D_CPU0_SB_DQ<0>")
	)
	(segment
		(start 295.340786 -230.04272)
		(end 294.964104 -230.04272)
		(width 0.18288)
		(layer "In11.Cu")
		(net "M_D_CPU0_SB_DQ<0>")
	)
	(segment
		(start 346.239338 -241.968528)
		(end 346.236036 -241.97056)
		(width 0.088646)
		(layer "In11.Cu")
		(net "M_D_CPU0_SB_DQ<0>")
	)
	(segment
		(start 289.397694 -229.874826)
		(end 288.127694 -228.604826)
		(width 0.18288)
		(layer "In11.Cu")
		(net "M_D_CPU0_SB_DQ<0>")
	)
	(segment
		(start 338.166964 -241.979196)
		(end 338.152232 -241.97056)
		(width 0.088646)
		(layer "In11.Cu")
		(net "M_D_CPU0_SB_DQ<0>")
	)
	(segment
		(start 335.050384 -241.496596)
		(end 335.050384 -241.481102)
		(width 0.088646)
		(layer "In11.Cu")
		(net "M_D_CPU0_SB_DQ<0>")
	)
	(segment
		(start 304.790094 -230.027226)
		(end 303.393094 -228.630226)
		(width 0.18288)
		(layer "In11.Cu")
		(net "M_D_CPU0_SB_DQ<0>")
	)
	(segment
		(start 337.227164 -241.979196)
		(end 337.212432 -241.97056)
		(width 0.088646)
		(layer "In11.Cu")
		(net "M_D_CPU0_SB_DQ<0>")
	)
	(segment
		(start 273.982688 -232.602278)
		(end 273.879818 -232.499408)
		(width 0.18288)
		(layer "In11.Cu")
		(net "M_D_CPU0_SB_DQ<0>")
	)
	(segment
		(start 280.253186 -230.04272)
		(end 279.87244 -230.04272)
		(width 0.18288)
		(layer "In11.Cu")
		(net "M_D_CPU0_SB_DQ<0>")
	)
	(segment
		(start 312.307986 -231.551226)
		(end 310.466486 -231.551226)
		(width 0.18288)
		(layer "In11.Cu")
		(net "M_D_CPU0_SB_DQ<0>")
	)
	(segment
		(start 345.685364 -241.979196)
		(end 345.670632 -241.97056)
		(width 0.088646)
		(layer "In11.Cu")
		(net "M_D_CPU0_SB_DQ<0>")
	)
	(segment
		(start 339.106764 -241.979196)
		(end 339.092032 -241.97056)
		(width 0.088646)
		(layer "In11.Cu")
		(net "M_D_CPU0_SB_DQ<0>")
	)
	(segment
		(start 301.687484 -228.823266)
		(end 301.687484 -229.287324)
		(width 0.18288)
		(layer "In11.Cu")
		(net "M_D_CPU0_SB_DQ<0>")
	)
	(segment
		(start 309.6768 -231.744012)
		(end 308.671214 -230.738426)
		(width 0.18288)
		(layer "In11.Cu")
		(net "M_D_CPU0_SB_DQ<0>")
	)
	(segment
		(start 346.89288 -241.481102)
		(end 346.89288 -241.51209)
		(width 0.088646)
		(layer "In11.Cu")
		(net "M_D_CPU0_SB_DQ<0>")
	)
	(segment
		(start 284.354524 -229.191312)
		(end 282.613608 -229.191312)
		(width 0.18288)
		(layer "In11.Cu")
		(net "M_D_CPU0_SB_DQ<0>")
	)
	(segment
		(start 332.32598 -240.292128)
		(end 332.002384 -240.292128)
		(width 0.088646)
		(layer "In11.Cu")
		(net "M_D_CPU0_SB_DQ<0>")
	)
	(segment
		(start 279.872186 -230.042466)
		(end 279.762966 -230.042466)
		(width 0.18288)
		(layer "In11.Cu")
		(net "M_D_CPU0_SB_DQ<0>")
	)
	(segment
		(start 333.640684 -240.677192)
		(end 333.640684 -240.667286)
		(width 0.088646)
		(layer "In11.Cu")
		(net "M_D_CPU0_SB_DQ<0>")
	)
	(segment
		(start 300.986444 -229.287324)
		(end 300.986444 -228.823266)
		(width 0.18288)
		(layer "In11.Cu")
		(net "M_D_CPU0_SB_DQ<0>")
	)
	(segment
		(start 280.49728 -229.798626)
		(end 280.253186 -230.04272)
		(width 0.18288)
		(layer "In11.Cu")
		(net "M_D_CPU0_SB_DQ<0>")
	)
	(segment
		(start 275.945854 -231.271826)
		(end 274.615402 -232.602278)
		(width 0.18288)
		(layer "In11.Cu")
		(net "M_D_CPU0_SB_DQ<0>")
	)
	(arc
		(start 339.092032 -241.97056)
		(mid 338.904834 -241.920417)
		(end 338.717636 -241.97056)
		(width 0.088646)
		(layer "In11.Cu")
		(net "M_D_CPU0_SB_DQ<0>")
	)
	(arc
		(start 338.152232 -241.97056)
		(mid 337.965034 -241.920417)
		(end 337.777836 -241.97056)
		(width 0.088646)
		(layer "In11.Cu")
		(net "M_D_CPU0_SB_DQ<0>")
	)
	(arc
		(start 341.537036 -241.97056)
		(mid 341.262837 -242.046395)
		(end 340.986364 -241.979196)
		(width 0.088646)
		(layer "In11.Cu")
		(net "M_D_CPU0_SB_DQ<0>")
	)
	(arc
		(start 335.332578 -241.97056)
		(mid 335.129755 -241.770329)
		(end 335.050384 -241.496596)
		(width 0.088646)
		(layer "In11.Cu")
		(net "M_D_CPU0_SB_DQ<0>")
	)
	(arc
		(start 335.050384 -241.481102)
		(mid 335.002705 -241.298202)
		(end 334.871822 -241.161824)
		(width 0.088646)
		(layer "In11.Cu")
		(net "M_D_CPU0_SB_DQ<0>")
	)
	(arc
		(start 332.513432 -240.342928)
		(mid 332.423053 -240.305173)
		(end 332.32598 -240.292128)
		(width 0.088646)
		(layer "In11.Cu")
		(net "M_D_CPU0_SB_DQ<0>")
	)
	(arc
		(start 346.508578 -241.896392)
		(mid 346.369199 -241.914702)
		(end 346.239338 -241.968528)
		(width 0.088646)
		(layer "In11.Cu")
		(net "M_D_CPU0_SB_DQ<0>")
	)
	(arc
		(start 337.212432 -241.97056)
		(mid 337.025234 -241.920417)
		(end 336.838036 -241.97056)
		(width 0.088646)
		(layer "In11.Cu")
		(net "M_D_CPU0_SB_DQ<0>")
	)
	(arc
		(start 333.078836 -240.342928)
		(mid 332.804607 -240.418853)
		(end 332.528164 -240.351564)
		(width 0.088646)
		(layer "In11.Cu")
		(net "M_D_CPU0_SB_DQ<0>")
	)
	(arc
		(start 343.416636 -241.97056)
		(mid 343.142437 -242.046395)
		(end 342.865964 -241.979196)
		(width 0.088646)
		(layer "In11.Cu")
		(net "M_D_CPU0_SB_DQ<0>")
	)
	(arc
		(start 337.777836 -241.97056)
		(mid 337.503637 -242.046395)
		(end 337.227164 -241.979196)
		(width 0.088646)
		(layer "In11.Cu")
		(net "M_D_CPU0_SB_DQ<0>")
	)
	(arc
		(start 333.453232 -240.342928)
		(mid 333.266034 -240.292785)
		(end 333.078836 -240.342928)
		(width 0.088646)
		(layer "In11.Cu")
		(net "M_D_CPU0_SB_DQ<0>")
	)
	(arc
		(start 335.89849 -241.97056)
		(mid 335.615534 -242.046463)
		(end 335.332578 -241.97056)
		(width 0.088646)
		(layer "In11.Cu")
		(net "M_D_CPU0_SB_DQ<0>")
	)
	(arc
		(start 340.597236 -241.97056)
		(mid 340.323037 -242.046395)
		(end 340.046564 -241.979196)
		(width 0.088646)
		(layer "In11.Cu")
		(net "M_D_CPU0_SB_DQ<0>")
	)
	(arc
		(start 346.89288 -241.51209)
		(mid 346.780321 -241.783833)
		(end 346.508578 -241.896392)
		(width 0.088646)
		(layer "In11.Cu")
		(net "M_D_CPU0_SB_DQ<0>")
	)
	(arc
		(start 343.791032 -241.97056)
		(mid 343.603834 -241.920417)
		(end 343.416636 -241.97056)
		(width 0.088646)
		(layer "In11.Cu")
		(net "M_D_CPU0_SB_DQ<0>")
	)
	(arc
		(start 334.488536 -241.156744)
		(mid 334.205834 -241.23252)
		(end 333.923132 -241.156744)
		(width 0.088646)
		(layer "In11.Cu")
		(net "M_D_CPU0_SB_DQ<0>")
	)
	(arc
		(start 340.971632 -241.97056)
		(mid 340.784434 -241.920417)
		(end 340.597236 -241.97056)
		(width 0.088646)
		(layer "In11.Cu")
		(net "M_D_CPU0_SB_DQ<0>")
	)
	(arc
		(start 334.862932 -241.156744)
		(mid 334.675734 -241.106601)
		(end 334.488536 -241.156744)
		(width 0.088646)
		(layer "In11.Cu")
		(net "M_D_CPU0_SB_DQ<0>")
	)
	(arc
		(start 333.640684 -240.667286)
		(mid 333.593005 -240.484386)
		(end 333.462122 -240.348008)
		(width 0.088646)
		(layer "In11.Cu")
		(net "M_D_CPU0_SB_DQ<0>")
	)
	(arc
		(start 346.236036 -241.97056)
		(mid 345.961837 -242.046395)
		(end 345.685364 -241.979196)
		(width 0.088646)
		(layer "In11.Cu")
		(net "M_D_CPU0_SB_DQ<0>")
	)
	(arc
		(start 338.717636 -241.97056)
		(mid 338.443437 -242.046395)
		(end 338.166964 -241.979196)
		(width 0.088646)
		(layer "In11.Cu")
		(net "M_D_CPU0_SB_DQ<0>")
	)
	(arc
		(start 344.730832 -241.97056)
		(mid 344.543634 -241.920417)
		(end 344.356436 -241.97056)
		(width 0.088646)
		(layer "In11.Cu")
		(net "M_D_CPU0_SB_DQ<0>")
	)
	(arc
		(start 345.296236 -241.97056)
		(mid 345.022037 -242.046395)
		(end 344.745564 -241.979196)
		(width 0.088646)
		(layer "In11.Cu")
		(net "M_D_CPU0_SB_DQ<0>")
	)
	(arc
		(start 339.657436 -241.97056)
		(mid 339.383237 -242.046395)
		(end 339.106764 -241.979196)
		(width 0.088646)
		(layer "In11.Cu")
		(net "M_D_CPU0_SB_DQ<0>")
	)
	(arc
		(start 341.911432 -241.97056)
		(mid 341.724234 -241.920417)
		(end 341.537036 -241.97056)
		(width 0.088646)
		(layer "In11.Cu")
		(net "M_D_CPU0_SB_DQ<0>")
	)
	(arc
		(start 345.670632 -241.97056)
		(mid 345.483434 -241.920417)
		(end 345.296236 -241.97056)
		(width 0.088646)
		(layer "In11.Cu")
		(net "M_D_CPU0_SB_DQ<0>")
	)
	(arc
		(start 342.476836 -241.97056)
		(mid 342.194134 -242.046336)
		(end 341.911432 -241.97056)
		(width 0.088646)
		(layer "In11.Cu")
		(net "M_D_CPU0_SB_DQ<0>")
	)
	(arc
		(start 336.26425 -241.965734)
		(mid 336.080742 -241.920456)
		(end 335.89849 -241.97056)
		(width 0.088646)
		(layer "In11.Cu")
		(net "M_D_CPU0_SB_DQ<0>")
	)
	(arc
		(start 344.356436 -241.97056)
		(mid 344.082237 -242.046395)
		(end 343.805764 -241.979196)
		(width 0.088646)
		(layer "In11.Cu")
		(net "M_D_CPU0_SB_DQ<0>")
	)
	(arc
		(start 333.923132 -241.156744)
		(mid 333.718797 -240.954139)
		(end 333.640684 -240.677192)
		(width 0.088646)
		(layer "In11.Cu")
		(net "M_D_CPU0_SB_DQ<0>")
	)
	(arc
		(start 342.851232 -241.97056)
		(mid 342.664034 -241.920417)
		(end 342.476836 -241.97056)
		(width 0.088646)
		(layer "In11.Cu")
		(net "M_D_CPU0_SB_DQ<0>")
	)
	(arc
		(start 340.031832 -241.97056)
		(mid 339.844634 -241.920417)
		(end 339.657436 -241.97056)
		(width 0.088646)
		(layer "In11.Cu")
		(net "M_D_CPU0_SB_DQ<0>")
	)
	(arc
		(start 336.838036 -241.97056)
		(mid 336.563837 -242.046395)
		(end 336.287364 -241.979196)
		(width 0.088646)
		(layer "In11.Cu")
		(net "M_D_CPU0_SB_DQ<0>")
	)
	(segment
		(start 343.603834 -246.086376)
		(end 343.603834 -245.55069)
		(width 0.20066)
		(layer "F.Cu")
		(net "M_D_CPU0_SB_CS_N<3>")
	)
	(segment
		(start 343.60358 -246.08663)
		(end 343.603834 -246.086376)
		(width 0.20066)
		(layer "F.Cu")
		(net "M_D_CPU0_SB_CS_N<3>")
	)
	(segment
		(start 268.829282 -244.916706)
		(end 267.724382 -244.916706)
		(width 0.20066)
		(layer "F.Cu")
		(net "M_D_CPU0_SB_CS_N<3>")
	)
	(segment
		(start 339.102192 -245.868952)
		(end 339.091778 -245.875048)
		(width 0.088646)
		(layer "In6.Cu")
		(net "M_D_CPU0_SB_CS_N<3>")
	)
	(segment
		(start 295.917366 -242.097306)
		(end 295.760902 -241.940842)
		(width 0.18288)
		(layer "In6.Cu")
		(net "M_D_CPU0_SB_CS_N<3>")
	)
	(segment
		(start 331.693266 -246.01043)
		(end 331.552804 -246.34952)
		(width 0.088646)
		(layer "In6.Cu")
		(net "M_D_CPU0_SB_CS_N<3>")
	)
	(segment
		(start 305.95189 -241.940842)
		(end 303.882806 -241.940842)
		(width 0.18288)
		(layer "In6.Cu")
		(net "M_D_CPU0_SB_CS_N<3>")
	)
	(segment
		(start 331.552804 -246.48287)
		(end 331.380846 -246.654828)
		(width 0.088646)
		(layer "In6.Cu")
		(net "M_D_CPU0_SB_CS_N<3>")
	)
	(segment
		(start 299.707046 -241.940842)
		(end 297.79087 -241.940842)
		(width 0.18288)
		(layer "In6.Cu")
		(net "M_D_CPU0_SB_CS_N<3>")
	)
	(segment
		(start 275.196808 -241.591592)
		(end 274.823428 -241.591592)
		(width 0.18288)
		(layer "In6.Cu")
		(net "M_D_CPU0_SB_CS_N<3>")
	)
	(segment
		(start 285.755334 -241.99977)
		(end 285.572454 -241.81689)
		(width 0.18288)
		(layer "In6.Cu")
		(net "M_D_CPU0_SB_CS_N<3>")
	)
	(segment
		(start 280.710386 -241.941096)
		(end 279.388062 -241.941096)
		(width 0.18288)
		(layer "In6.Cu")
		(net "M_D_CPU0_SB_CS_N<3>")
	)
	(segment
		(start 306.103782 -242.092734)
		(end 305.95189 -241.940842)
		(width 0.18288)
		(layer "In6.Cu")
		(net "M_D_CPU0_SB_CS_N<3>")
	)
	(segment
		(start 273.921728 -242.228624)
		(end 273.020028 -241.326924)
		(width 0.18288)
		(layer "In6.Cu")
		(net "M_D_CPU0_SB_CS_N<3>")
	)
	(segment
		(start 342.759284 -246.373142)
		(end 342.759284 -246.3546)
		(width 0.088646)
		(layer "In6.Cu")
		(net "M_D_CPU0_SB_CS_N<3>")
	)
	(segment
		(start 285.938214 -242.374674)
		(end 285.755334 -242.191794)
		(width 0.18288)
		(layer "In6.Cu")
		(net "M_D_CPU0_SB_CS_N<3>")
	)
	(segment
		(start 343.916508 -245.55069)
		(end 343.973912 -245.608094)
		(width 0.088646)
		(layer "In6.Cu")
		(net "M_D_CPU0_SB_CS_N<3>")
	)
	(segment
		(start 285.755334 -242.191794)
		(end 285.755334 -241.99977)
		(width 0.18288)
		(layer "In6.Cu")
		(net "M_D_CPU0_SB_CS_N<3>")
	)
	(segment
		(start 310.655208 -241.838226)
		(end 307.545994 -241.838226)
		(width 0.18288)
		(layer "In6.Cu")
		(net "M_D_CPU0_SB_CS_N<3>")
	)
	(segment
		(start 276.149562 -241.940842)
		(end 275.86178 -242.228624)
		(width 0.18288)
		(layer "In6.Cu")
		(net "M_D_CPU0_SB_CS_N<3>")
	)
	(segment
		(start 274.503388 -242.228624)
		(end 273.921728 -242.228624)
		(width 0.18288)
		(layer "In6.Cu")
		(net "M_D_CPU0_SB_CS_N<3>")
	)
	(segment
		(start 331.862938 -245.840758)
		(end 331.693266 -246.01043)
		(width 0.088646)
		(layer "In6.Cu")
		(net "M_D_CPU0_SB_CS_N<3>")
	)
	(segment
		(start 286.446214 -242.191794)
		(end 286.263334 -242.374674)
		(width 0.18288)
		(layer "In6.Cu")
		(net "M_D_CPU0_SB_CS_N<3>")
	)
	(segment
		(start 313.254644 -243.0018)
		(end 312.194956 -241.942112)
		(width 0.18288)
		(layer "In6.Cu")
		(net "M_D_CPU0_SB_CS_N<3>")
	)
	(segment
		(start 274.663408 -242.068604)
		(end 274.503388 -242.228624)
		(width 0.18288)
		(layer "In6.Cu")
		(net "M_D_CPU0_SB_CS_N<3>")
	)
	(segment
		(start 332.104746 -245.840758)
		(end 331.862938 -245.840758)
		(width 0.088646)
		(layer "In6.Cu")
		(net "M_D_CPU0_SB_CS_N<3>")
	)
	(segment
		(start 340.042246 -245.868952)
		(end 340.031832 -245.875048)
		(width 0.088646)
		(layer "In6.Cu")
		(net "M_D_CPU0_SB_CS_N<3>")
	)
	(segment
		(start 269.553436 -243.93398)
		(end 269.553436 -244.192552)
		(width 0.18288)
		(layer "In6.Cu")
		(net "M_D_CPU0_SB_CS_N<3>")
	)
	(segment
		(start 269.491714 -243.153438)
		(end 269.26159 -243.383562)
		(width 0.18288)
		(layer "In6.Cu")
		(net "M_D_CPU0_SB_CS_N<3>")
	)
	(segment
		(start 275.86178 -242.228624)
		(end 275.516848 -242.228624)
		(width 0.18288)
		(layer "In6.Cu")
		(net "M_D_CPU0_SB_CS_N<3>")
	)
	(segment
		(start 269.26159 -243.642134)
		(end 269.553436 -243.93398)
		(width 0.18288)
		(layer "In6.Cu")
		(net "M_D_CPU0_SB_CS_N<3>")
	)
	(segment
		(start 301.524162 -241.374676)
		(end 301.177198 -241.72164)
		(width 0.18288)
		(layer "In6.Cu")
		(net "M_D_CPU0_SB_CS_N<3>")
	)
	(segment
		(start 285.572454 -241.81689)
		(end 284.86608 -241.81689)
		(width 0.18288)
		(layer "In6.Cu")
		(net "M_D_CPU0_SB_CS_N<3>")
	)
	(segment
		(start 297.634406 -242.097306)
		(end 295.917366 -242.097306)
		(width 0.18288)
		(layer "In6.Cu")
		(net "M_D_CPU0_SB_CS_N<3>")
	)
	(segment
		(start 338.162646 -245.868952)
		(end 338.152232 -245.875048)
		(width 0.088646)
		(layer "In6.Cu")
		(net "M_D_CPU0_SB_CS_N<3>")
	)
	(segment
		(start 331.131418 -246.654828)
		(end 330.294996 -246.654828)
		(width 0.18288)
		(layer "In6.Cu")
		(net "M_D_CPU0_SB_CS_N<3>")
	)
	(segment
		(start 307.291486 -242.092734)
		(end 306.103782 -242.092734)
		(width 0.18288)
		(layer "In6.Cu")
		(net "M_D_CPU0_SB_CS_N<3>")
	)
	(segment
		(start 317.443866 -245.531132)
		(end 314.914534 -243.0018)
		(width 0.18288)
		(layer "In6.Cu")
		(net "M_D_CPU0_SB_CS_N<3>")
	)
	(segment
		(start 282.472892 -242.089686)
		(end 280.858976 -242.089686)
		(width 0.18288)
		(layer "In6.Cu")
		(net "M_D_CPU0_SB_CS_N<3>")
	)
	(segment
		(start 277.247096 -241.608356)
		(end 276.91461 -241.940842)
		(width 0.18288)
		(layer "In6.Cu")
		(net "M_D_CPU0_SB_CS_N<3>")
	)
	(segment
		(start 299.926248 -241.72164)
		(end 299.707046 -241.940842)
		(width 0.18288)
		(layer "In6.Cu")
		(net "M_D_CPU0_SB_CS_N<3>")
	)
	(segment
		(start 290.103814 -242.485926)
		(end 289.02152 -242.485926)
		(width 0.18288)
		(layer "In6.Cu")
		(net "M_D_CPU0_SB_CS_N<3>")
	)
	(segment
		(start 275.516848 -242.228624)
		(end 275.356828 -242.068604)
		(width 0.18288)
		(layer "In6.Cu")
		(net "M_D_CPU0_SB_CS_N<3>")
	)
	(segment
		(start 286.263334 -242.374674)
		(end 285.938214 -242.374674)
		(width 0.18288)
		(layer "In6.Cu")
		(net "M_D_CPU0_SB_CS_N<3>")
	)
	(segment
		(start 284.741874 -241.941096)
		(end 282.621482 -241.941096)
		(width 0.18288)
		(layer "In6.Cu")
		(net "M_D_CPU0_SB_CS_N<3>")
	)
	(segment
		(start 269.553436 -244.192552)
		(end 268.829282 -244.916706)
		(width 0.18288)
		(layer "In6.Cu")
		(net "M_D_CPU0_SB_CS_N<3>")
	)
	(segment
		(start 270.8656 -242.880388)
		(end 270.300704 -243.445284)
		(width 0.18288)
		(layer "In6.Cu")
		(net "M_D_CPU0_SB_CS_N<3>")
	)
	(segment
		(start 303.882806 -241.940842)
		(end 303.31664 -241.374676)
		(width 0.18288)
		(layer "In6.Cu")
		(net "M_D_CPU0_SB_CS_N<3>")
	)
	(segment
		(start 331.552804 -246.34952)
		(end 331.552804 -246.48287)
		(width 0.088646)
		(layer "In6.Cu")
		(net "M_D_CPU0_SB_CS_N<3>")
	)
	(segment
		(start 290.648644 -241.941096)
		(end 290.103814 -242.485926)
		(width 0.18288)
		(layer "In6.Cu")
		(net "M_D_CPU0_SB_CS_N<3>")
	)
	(segment
		(start 275.356828 -242.068604)
		(end 275.356828 -241.751612)
		(width 0.18288)
		(layer "In6.Cu")
		(net "M_D_CPU0_SB_CS_N<3>")
	)
	(segment
		(start 276.91461 -241.940842)
		(end 276.149562 -241.940842)
		(width 0.18288)
		(layer "In6.Cu")
		(net "M_D_CPU0_SB_CS_N<3>")
	)
	(segment
		(start 270.042132 -243.445284)
		(end 269.750286 -243.153438)
		(width 0.18288)
		(layer "In6.Cu")
		(net "M_D_CPU0_SB_CS_N<3>")
	)
	(segment
		(start 337.227164 -245.866412)
		(end 337.212432 -245.875048)
		(width 0.088646)
		(layer "In6.Cu")
		(net "M_D_CPU0_SB_CS_N<3>")
	)
	(segment
		(start 321.088512 -245.068344)
		(end 320.625724 -245.531132)
		(width 0.18288)
		(layer "In6.Cu")
		(net "M_D_CPU0_SB_CS_N<3>")
	)
	(segment
		(start 289.02152 -242.485926)
		(end 288.352484 -241.81689)
		(width 0.18288)
		(layer "In6.Cu")
		(net "M_D_CPU0_SB_CS_N<3>")
	)
	(segment
		(start 314.914534 -243.0018)
		(end 313.254644 -243.0018)
		(width 0.18288)
		(layer "In6.Cu")
		(net "M_D_CPU0_SB_CS_N<3>")
	)
	(segment
		(start 295.760902 -241.940842)
		(end 295.034208 -241.940842)
		(width 0.18288)
		(layer "In6.Cu")
		(net "M_D_CPU0_SB_CS_N<3>")
	)
	(segment
		(start 328.708512 -245.068344)
		(end 321.088512 -245.068344)
		(width 0.18288)
		(layer "In6.Cu")
		(net "M_D_CPU0_SB_CS_N<3>")
	)
	(segment
		(start 286.446214 -241.99977)
		(end 286.446214 -242.191794)
		(width 0.18288)
		(layer "In6.Cu")
		(net "M_D_CPU0_SB_CS_N<3>")
	)
	(segment
		(start 297.79087 -241.940842)
		(end 297.634406 -242.097306)
		(width 0.18288)
		(layer "In6.Cu")
		(net "M_D_CPU0_SB_CS_N<3>")
	)
	(segment
		(start 312.194956 -241.942112)
		(end 310.759094 -241.942112)
		(width 0.18288)
		(layer "In6.Cu")
		(net "M_D_CPU0_SB_CS_N<3>")
	)
	(segment
		(start 343.329768 -246.683784)
		(end 343.320878 -246.688864)
		(width 0.088646)
		(layer "In6.Cu")
		(net "M_D_CPU0_SB_CS_N<3>")
	)
	(segment
		(start 270.300704 -243.445284)
		(end 270.042132 -243.445284)
		(width 0.18288)
		(layer "In6.Cu")
		(net "M_D_CPU0_SB_CS_N<3>")
	)
	(segment
		(start 284.86608 -241.81689)
		(end 284.741874 -241.941096)
		(width 0.18288)
		(layer "In6.Cu")
		(net "M_D_CPU0_SB_CS_N<3>")
	)
	(segment
		(start 275.356828 -241.751612)
		(end 275.196808 -241.591592)
		(width 0.18288)
		(layer "In6.Cu")
		(net "M_D_CPU0_SB_CS_N<3>")
	)
	(segment
		(start 301.177198 -241.72164)
		(end 299.926248 -241.72164)
		(width 0.18288)
		(layer "In6.Cu")
		(net "M_D_CPU0_SB_CS_N<3>")
	)
	(segment
		(start 343.791032 -245.875048)
		(end 343.784936 -245.878604)
		(width 0.088646)
		(layer "In6.Cu")
		(net "M_D_CPU0_SB_CS_N<3>")
	)
	(segment
		(start 273.020028 -241.326924)
		(end 271.879314 -241.326924)
		(width 0.18288)
		(layer "In6.Cu")
		(net "M_D_CPU0_SB_CS_N<3>")
	)
	(segment
		(start 330.294996 -246.654828)
		(end 328.708512 -245.068344)
		(width 0.18288)
		(layer "In6.Cu")
		(net "M_D_CPU0_SB_CS_N<3>")
	)
	(segment
		(start 279.388062 -241.941096)
		(end 279.055322 -241.608356)
		(width 0.18288)
		(layer "In6.Cu")
		(net "M_D_CPU0_SB_CS_N<3>")
	)
	(segment
		(start 336.287364 -245.866412)
		(end 336.272632 -245.875048)
		(width 0.088646)
		(layer "In6.Cu")
		(net "M_D_CPU0_SB_CS_N<3>")
	)
	(segment
		(start 295.033954 -241.941096)
		(end 290.648644 -241.941096)
		(width 0.18288)
		(layer "In6.Cu")
		(net "M_D_CPU0_SB_CS_N<3>")
	)
	(segment
		(start 310.759094 -241.942112)
		(end 310.655208 -241.838226)
		(width 0.18288)
		(layer "In6.Cu")
		(net "M_D_CPU0_SB_CS_N<3>")
	)
	(segment
		(start 269.26159 -243.383562)
		(end 269.26159 -243.642134)
		(width 0.18288)
		(layer "In6.Cu")
		(net "M_D_CPU0_SB_CS_N<3>")
	)
	(segment
		(start 271.879314 -241.326924)
		(end 270.8656 -242.340638)
		(width 0.18288)
		(layer "In6.Cu")
		(net "M_D_CPU0_SB_CS_N<3>")
	)
	(segment
		(start 270.8656 -242.340638)
		(end 270.8656 -242.880388)
		(width 0.18288)
		(layer "In6.Cu")
		(net "M_D_CPU0_SB_CS_N<3>")
	)
	(segment
		(start 269.750286 -243.153438)
		(end 269.491714 -243.153438)
		(width 0.18288)
		(layer "In6.Cu")
		(net "M_D_CPU0_SB_CS_N<3>")
	)
	(segment
		(start 286.629094 -241.81689)
		(end 286.446214 -241.99977)
		(width 0.18288)
		(layer "In6.Cu")
		(net "M_D_CPU0_SB_CS_N<3>")
	)
	(segment
		(start 279.055322 -241.608356)
		(end 277.247096 -241.608356)
		(width 0.18288)
		(layer "In6.Cu")
		(net "M_D_CPU0_SB_CS_N<3>")
	)
	(segment
		(start 343.799922 -245.869968)
		(end 343.791032 -245.875048)
		(width 0.088646)
		(layer "In6.Cu")
		(net "M_D_CPU0_SB_CS_N<3>")
	)
	(segment
		(start 331.380846 -246.654828)
		(end 331.131418 -246.654828)
		(width 0.088646)
		(layer "In6.Cu")
		(net "M_D_CPU0_SB_CS_N<3>")
	)
	(segment
		(start 307.545994 -241.838226)
		(end 307.291486 -242.092734)
		(width 0.18288)
		(layer "In6.Cu")
		(net "M_D_CPU0_SB_CS_N<3>")
	)
	(segment
		(start 288.352484 -241.81689)
		(end 286.629094 -241.81689)
		(width 0.18288)
		(layer "In6.Cu")
		(net "M_D_CPU0_SB_CS_N<3>")
	)
	(segment
		(start 274.663408 -241.751612)
		(end 274.663408 -242.068604)
		(width 0.18288)
		(layer "In6.Cu")
		(net "M_D_CPU0_SB_CS_N<3>")
	)
	(segment
		(start 280.858976 -242.089686)
		(end 280.710386 -241.941096)
		(width 0.18288)
		(layer "In6.Cu")
		(net "M_D_CPU0_SB_CS_N<3>")
	)
	(segment
		(start 282.621482 -241.941096)
		(end 282.472892 -242.089686)
		(width 0.18288)
		(layer "In6.Cu")
		(net "M_D_CPU0_SB_CS_N<3>")
	)
	(segment
		(start 343.603834 -245.55069)
		(end 343.916508 -245.55069)
		(width 0.088646)
		(layer "In6.Cu")
		(net "M_D_CPU0_SB_CS_N<3>")
	)
	(segment
		(start 340.981792 -245.868952)
		(end 340.971378 -245.875048)
		(width 0.088646)
		(layer "In6.Cu")
		(net "M_D_CPU0_SB_CS_N<3>")
	)
	(segment
		(start 320.625724 -245.531132)
		(end 317.443866 -245.531132)
		(width 0.18288)
		(layer "In6.Cu")
		(net "M_D_CPU0_SB_CS_N<3>")
	)
	(segment
		(start 303.31664 -241.374676)
		(end 301.524162 -241.374676)
		(width 0.18288)
		(layer "In6.Cu")
		(net "M_D_CPU0_SB_CS_N<3>")
	)
	(segment
		(start 295.034208 -241.940842)
		(end 295.033954 -241.941096)
		(width 0.18288)
		(layer "In6.Cu")
		(net "M_D_CPU0_SB_CS_N<3>")
	)
	(segment
		(start 274.823428 -241.591592)
		(end 274.663408 -241.751612)
		(width 0.18288)
		(layer "In6.Cu")
		(net "M_D_CPU0_SB_CS_N<3>")
	)
	(segment
		(start 332.139036 -245.875048)
		(end 332.104746 -245.840758)
		(width 0.088646)
		(layer "In6.Cu")
		(net "M_D_CPU0_SB_CS_N<3>")
	)
	(arc
		(start 340.031832 -245.875048)
		(mid 339.844634 -245.925191)
		(end 339.657436 -245.875048)
		(width 0.088646)
		(layer "In6.Cu")
		(net "M_D_CPU0_SB_CS_N<3>")
	)
	(arc
		(start 337.777836 -245.875048)
		(mid 337.503637 -245.799213)
		(end 337.227164 -245.866412)
		(width 0.088646)
		(layer "In6.Cu")
		(net "M_D_CPU0_SB_CS_N<3>")
	)
	(arc
		(start 333.078836 -245.875048)
		(mid 332.796134 -245.799272)
		(end 332.513432 -245.875048)
		(width 0.088646)
		(layer "In6.Cu")
		(net "M_D_CPU0_SB_CS_N<3>")
	)
	(arc
		(start 338.152232 -245.875048)
		(mid 337.965034 -245.925191)
		(end 337.777836 -245.875048)
		(width 0.088646)
		(layer "In6.Cu")
		(net "M_D_CPU0_SB_CS_N<3>")
	)
	(arc
		(start 342.476836 -245.875048)
		(mid 342.194134 -245.799272)
		(end 341.911432 -245.875048)
		(width 0.088646)
		(layer "In6.Cu")
		(net "M_D_CPU0_SB_CS_N<3>")
	)
	(arc
		(start 342.946482 -246.688864)
		(mid 342.811549 -246.55551)
		(end 342.759284 -246.373142)
		(width 0.088646)
		(layer "In6.Cu")
		(net "M_D_CPU0_SB_CS_N<3>")
	)
	(arc
		(start 341.537036 -245.875048)
		(mid 341.260223 -245.799178)
		(end 340.981792 -245.868952)
		(width 0.088646)
		(layer "In6.Cu")
		(net "M_D_CPU0_SB_CS_N<3>")
	)
	(arc
		(start 336.838036 -245.875048)
		(mid 336.563837 -245.799213)
		(end 336.287364 -245.866412)
		(width 0.088646)
		(layer "In6.Cu")
		(net "M_D_CPU0_SB_CS_N<3>")
	)
	(arc
		(start 334.393032 -245.875048)
		(mid 334.205834 -245.925191)
		(end 334.018636 -245.875048)
		(width 0.088646)
		(layer "In6.Cu")
		(net "M_D_CPU0_SB_CS_N<3>")
	)
	(arc
		(start 338.717382 -245.875048)
		(mid 338.440823 -245.799305)
		(end 338.162646 -245.868952)
		(width 0.088646)
		(layer "In6.Cu")
		(net "M_D_CPU0_SB_CS_N<3>")
	)
	(arc
		(start 343.784936 -245.878604)
		(mid 343.582349 -246.084955)
		(end 343.50833 -246.364506)
		(width 0.088646)
		(layer "In6.Cu")
		(net "M_D_CPU0_SB_CS_N<3>")
	)
	(arc
		(start 333.453232 -245.875048)
		(mid 333.266034 -245.925191)
		(end 333.078836 -245.875048)
		(width 0.088646)
		(layer "In6.Cu")
		(net "M_D_CPU0_SB_CS_N<3>")
	)
	(arc
		(start 342.759284 -246.3546)
		(mid 342.681173 -246.077651)
		(end 342.476836 -245.875048)
		(width 0.088646)
		(layer "In6.Cu")
		(net "M_D_CPU0_SB_CS_N<3>")
	)
	(arc
		(start 343.973912 -245.608094)
		(mid 343.915756 -245.758207)
		(end 343.799922 -245.869968)
		(width 0.088646)
		(layer "In6.Cu")
		(net "M_D_CPU0_SB_CS_N<3>")
	)
	(arc
		(start 336.272632 -245.875048)
		(mid 336.085434 -245.925191)
		(end 335.898236 -245.875048)
		(width 0.088646)
		(layer "In6.Cu")
		(net "M_D_CPU0_SB_CS_N<3>")
	)
	(arc
		(start 335.898236 -245.875048)
		(mid 335.615534 -245.799272)
		(end 335.332832 -245.875048)
		(width 0.088646)
		(layer "In6.Cu")
		(net "M_D_CPU0_SB_CS_N<3>")
	)
	(arc
		(start 332.513432 -245.875048)
		(mid 332.326234 -245.925191)
		(end 332.139036 -245.875048)
		(width 0.088646)
		(layer "In6.Cu")
		(net "M_D_CPU0_SB_CS_N<3>")
	)
	(arc
		(start 334.958436 -245.875048)
		(mid 334.675734 -245.799272)
		(end 334.393032 -245.875048)
		(width 0.088646)
		(layer "In6.Cu")
		(net "M_D_CPU0_SB_CS_N<3>")
	)
	(arc
		(start 341.911432 -245.875048)
		(mid 341.724234 -245.925191)
		(end 341.537036 -245.875048)
		(width 0.088646)
		(layer "In6.Cu")
		(net "M_D_CPU0_SB_CS_N<3>")
	)
	(arc
		(start 339.657436 -245.875048)
		(mid 339.380623 -245.799178)
		(end 339.102192 -245.868952)
		(width 0.088646)
		(layer "In6.Cu")
		(net "M_D_CPU0_SB_CS_N<3>")
	)
	(arc
		(start 337.212432 -245.875048)
		(mid 337.025234 -245.925191)
		(end 336.838036 -245.875048)
		(width 0.088646)
		(layer "In6.Cu")
		(net "M_D_CPU0_SB_CS_N<3>")
	)
	(arc
		(start 340.971378 -245.875048)
		(mid 340.78418 -245.925191)
		(end 340.596982 -245.875048)
		(width 0.088646)
		(layer "In6.Cu")
		(net "M_D_CPU0_SB_CS_N<3>")
	)
	(arc
		(start 340.596982 -245.875048)
		(mid 340.320423 -245.799305)
		(end 340.042246 -245.868952)
		(width 0.088646)
		(layer "In6.Cu")
		(net "M_D_CPU0_SB_CS_N<3>")
	)
	(arc
		(start 339.091778 -245.875048)
		(mid 338.90458 -245.925191)
		(end 338.717382 -245.875048)
		(width 0.088646)
		(layer "In6.Cu")
		(net "M_D_CPU0_SB_CS_N<3>")
	)
	(arc
		(start 335.332832 -245.875048)
		(mid 335.145634 -245.925191)
		(end 334.958436 -245.875048)
		(width 0.088646)
		(layer "In6.Cu")
		(net "M_D_CPU0_SB_CS_N<3>")
	)
	(arc
		(start 343.320878 -246.688864)
		(mid 343.13368 -246.739007)
		(end 342.946482 -246.688864)
		(width 0.088646)
		(layer "In6.Cu")
		(net "M_D_CPU0_SB_CS_N<3>")
	)
	(arc
		(start 343.50833 -246.364506)
		(mid 343.460651 -246.547406)
		(end 343.329768 -246.683784)
		(width 0.088646)
		(layer "In6.Cu")
		(net "M_D_CPU0_SB_CS_N<3>")
	)
	(arc
		(start 334.018636 -245.875048)
		(mid 333.735934 -245.799272)
		(end 333.453232 -245.875048)
		(width 0.088646)
		(layer "In6.Cu")
		(net "M_D_CPU0_SB_CS_N<3>")
	)
	(segment
		(start 344.543634 -246.086376)
		(end 344.543634 -245.55069)
		(width 0.20066)
		(layer "F.Cu")
		(net "M_D_CPU0_SB_CS_N<2>")
	)
	(segment
		(start 344.54338 -246.08663)
		(end 344.543634 -246.086376)
		(width 0.20066)
		(layer "F.Cu")
		(net "M_D_CPU0_SB_CS_N<2>")
	)
	(segment
		(start 264.729214 -245.76659)
		(end 263.624314 -245.76659)
		(width 0.20066)
		(layer "F.Cu")
		(net "M_D_CPU0_SB_CS_N<2>")
	)
	(segment
		(start 289.011614 -243.255546)
		(end 288.367216 -242.611148)
		(width 0.18288)
		(layer "In6.Cu")
		(net "M_D_CPU0_SB_CS_N<2>")
	)
	(segment
		(start 331.663548 -246.999506)
		(end 331.460602 -246.999506)
		(width 0.088646)
		(layer "In6.Cu")
		(net "M_D_CPU0_SB_CS_N<2>")
	)
	(segment
		(start 281.438858 -242.79098)
		(end 273.514058 -242.79098)
		(width 0.18288)
		(layer "In6.Cu")
		(net "M_D_CPU0_SB_CS_N<2>")
	)
	(segment
		(start 270.34617 -245.340886)
		(end 268.200886 -245.340886)
		(width 0.18288)
		(layer "In6.Cu")
		(net "M_D_CPU0_SB_CS_N<2>")
	)
	(segment
		(start 302.161194 -241.892836)
		(end 301.167292 -242.886738)
		(width 0.18288)
		(layer "In6.Cu")
		(net "M_D_CPU0_SB_CS_N<2>")
	)
	(segment
		(start 287.647634 -242.79098)
		(end 286.915606 -242.79098)
		(width 0.18288)
		(layer "In6.Cu")
		(net "M_D_CPU0_SB_CS_N<2>")
	)
	(segment
		(start 290.59378 -242.79098)
		(end 290.129214 -243.255546)
		(width 0.18288)
		(layer "In6.Cu")
		(net "M_D_CPU0_SB_CS_N<2>")
	)
	(segment
		(start 308.304184 -242.788948)
		(end 308.137306 -242.955826)
		(width 0.18288)
		(layer "In6.Cu")
		(net "M_D_CPU0_SB_CS_N<2>")
	)
	(segment
		(start 271.427194 -242.925092)
		(end 270.483838 -245.203218)
		(width 0.18288)
		(layer "In6.Cu")
		(net "M_D_CPU0_SB_CS_N<2>")
	)
	(segment
		(start 287.827466 -242.611148)
		(end 287.647634 -242.79098)
		(width 0.18288)
		(layer "In6.Cu")
		(net "M_D_CPU0_SB_CS_N<2>")
	)
	(segment
		(start 297.947842 -242.79098)
		(end 297.834304 -242.677442)
		(width 0.18288)
		(layer "In6.Cu")
		(net "M_D_CPU0_SB_CS_N<2>")
	)
	(segment
		(start 267.57376 -245.968012)
		(end 266.62888 -246.359426)
		(width 0.18288)
		(layer "In6.Cu")
		(net "M_D_CPU0_SB_CS_N<2>")
	)
	(segment
		(start 337.307682 -246.040148)
		(end 337.29295 -246.048784)
		(width 0.088646)
		(layer "In6.Cu")
		(net "M_D_CPU0_SB_CS_N<2>")
	)
	(segment
		(start 272.616168 -241.89309)
		(end 272.050256 -241.89309)
		(width 0.18288)
		(layer "In6.Cu")
		(net "M_D_CPU0_SB_CS_N<2>")
	)
	(segment
		(start 301.167292 -242.886738)
		(end 299.793152 -242.886738)
		(width 0.18288)
		(layer "In6.Cu")
		(net "M_D_CPU0_SB_CS_N<2>")
	)
	(segment
		(start 342.851232 -246.853964)
		(end 342.845136 -246.850408)
		(width 0.088646)
		(layer "In6.Cu")
		(net "M_D_CPU0_SB_CS_N<2>")
	)
	(segment
		(start 266.62888 -246.359426)
		(end 266.160504 -246.359426)
		(width 0.18288)
		(layer "In6.Cu")
		(net "M_D_CPU0_SB_CS_N<2>")
	)
	(segment
		(start 342.865964 -246.8626)
		(end 342.851232 -246.853964)
		(width 0.088646)
		(layer "In6.Cu")
		(net "M_D_CPU0_SB_CS_N<2>")
	)
	(segment
		(start 308.137306 -242.955826)
		(end 306.86375 -242.955826)
		(width 0.18288)
		(layer "In6.Cu")
		(net "M_D_CPU0_SB_CS_N<2>")
	)
	(segment
		(start 286.78632 -242.920266)
		(end 284.656784 -242.920266)
		(width 0.18288)
		(layer "In6.Cu")
		(net "M_D_CPU0_SB_CS_N<2>")
	)
	(segment
		(start 283.482034 -242.625626)
		(end 281.604212 -242.625626)
		(width 0.18288)
		(layer "In6.Cu")
		(net "M_D_CPU0_SB_CS_N<2>")
	)
	(segment
		(start 312.180986 -242.788948)
		(end 308.304184 -242.788948)
		(width 0.18288)
		(layer "In6.Cu")
		(net "M_D_CPU0_SB_CS_N<2>")
	)
	(segment
		(start 273.514058 -242.79098)
		(end 272.616168 -241.89309)
		(width 0.18288)
		(layer "In6.Cu")
		(net "M_D_CPU0_SB_CS_N<2>")
	)
	(segment
		(start 332.043532 -246.040148)
		(end 331.949552 -246.040148)
		(width 0.088646)
		(layer "In6.Cu")
		(net "M_D_CPU0_SB_CS_N<2>")
	)
	(segment
		(start 336.367882 -246.040148)
		(end 336.357468 -246.046244)
		(width 0.088646)
		(layer "In6.Cu")
		(net "M_D_CPU0_SB_CS_N<2>")
	)
	(segment
		(start 303.022762 -241.892836)
		(end 302.161194 -241.892836)
		(width 0.18288)
		(layer "In6.Cu")
		(net "M_D_CPU0_SB_CS_N<2>")
	)
	(segment
		(start 281.604212 -242.625626)
		(end 281.438858 -242.79098)
		(width 0.18288)
		(layer "In6.Cu")
		(net "M_D_CPU0_SB_CS_N<2>")
	)
	(segment
		(start 306.86375 -242.955826)
		(end 306.698904 -242.79098)
		(width 0.18288)
		(layer "In6.Cu")
		(net "M_D_CPU0_SB_CS_N<2>")
	)
	(segment
		(start 284.656784 -242.920266)
		(end 284.527498 -242.79098)
		(width 0.18288)
		(layer "In6.Cu")
		(net "M_D_CPU0_SB_CS_N<2>")
	)
	(segment
		(start 283.647388 -242.79098)
		(end 283.482034 -242.625626)
		(width 0.18288)
		(layer "In6.Cu")
		(net "M_D_CPU0_SB_CS_N<2>")
	)
	(segment
		(start 286.915606 -242.79098)
		(end 286.78632 -242.920266)
		(width 0.18288)
		(layer "In6.Cu")
		(net "M_D_CPU0_SB_CS_N<2>")
	)
	(segment
		(start 328.56932 -245.403878)
		(end 321.350386 -245.403878)
		(width 0.18288)
		(layer "In6.Cu")
		(net "M_D_CPU0_SB_CS_N<2>")
	)
	(segment
		(start 266.160504 -246.359426)
		(end 265.073384 -245.909084)
		(width 0.18288)
		(layer "In6.Cu")
		(net "M_D_CPU0_SB_CS_N<2>")
	)
	(segment
		(start 284.527498 -242.79098)
		(end 283.647388 -242.79098)
		(width 0.18288)
		(layer "In6.Cu")
		(net "M_D_CPU0_SB_CS_N<2>")
	)
	(segment
		(start 338.247482 -246.040148)
		(end 338.23275 -246.048784)
		(width 0.088646)
		(layer "In6.Cu")
		(net "M_D_CPU0_SB_CS_N<2>")
	)
	(segment
		(start 271.427194 -242.516152)
		(end 271.427194 -242.925092)
		(width 0.18288)
		(layer "In6.Cu")
		(net "M_D_CPU0_SB_CS_N<2>")
	)
	(segment
		(start 317.29553 -246.105426)
		(end 314.764928 -243.574824)
		(width 0.18288)
		(layer "In6.Cu")
		(net "M_D_CPU0_SB_CS_N<2>")
	)
	(segment
		(start 303.920906 -242.79098)
		(end 303.022762 -241.892836)
		(width 0.18288)
		(layer "In6.Cu")
		(net "M_D_CPU0_SB_CS_N<2>")
	)
	(segment
		(start 344.543634 -245.55069)
		(end 344.23096 -245.55069)
		(width 0.088646)
		(layer "In6.Cu")
		(net "M_D_CPU0_SB_CS_N<2>")
	)
	(segment
		(start 299.793152 -242.886738)
		(end 299.697394 -242.79098)
		(width 0.18288)
		(layer "In6.Cu")
		(net "M_D_CPU0_SB_CS_N<2>")
	)
	(segment
		(start 342.006936 -246.040148)
		(end 341.996522 -246.046244)
		(width 0.088646)
		(layer "In6.Cu")
		(net "M_D_CPU0_SB_CS_N<2>")
	)
	(segment
		(start 290.129214 -243.255546)
		(end 289.011614 -243.255546)
		(width 0.18288)
		(layer "In6.Cu")
		(net "M_D_CPU0_SB_CS_N<2>")
	)
	(segment
		(start 288.367216 -242.611148)
		(end 287.827466 -242.611148)
		(width 0.18288)
		(layer "In6.Cu")
		(net "M_D_CPU0_SB_CS_N<2>")
	)
	(segment
		(start 314.764928 -243.574824)
		(end 312.966862 -243.574824)
		(width 0.18288)
		(layer "In6.Cu")
		(net "M_D_CPU0_SB_CS_N<2>")
	)
	(segment
		(start 343.892378 -246.036592)
		(end 343.886282 -246.040148)
		(width 0.088646)
		(layer "In6.Cu")
		(net "M_D_CPU0_SB_CS_N<2>")
	)
	(segment
		(start 321.350386 -245.403878)
		(end 320.648838 -246.105426)
		(width 0.18288)
		(layer "In6.Cu")
		(net "M_D_CPU0_SB_CS_N<2>")
	)
	(segment
		(start 331.860906 -246.128794)
		(end 331.860906 -246.802148)
		(width 0.088646)
		(layer "In6.Cu")
		(net "M_D_CPU0_SB_CS_N<2>")
	)
	(segment
		(start 272.050256 -241.89309)
		(end 271.427194 -242.516152)
		(width 0.18288)
		(layer "In6.Cu")
		(net "M_D_CPU0_SB_CS_N<2>")
	)
	(segment
		(start 331.860906 -246.802148)
		(end 331.663548 -246.999506)
		(width 0.088646)
		(layer "In6.Cu")
		(net "M_D_CPU0_SB_CS_N<2>")
	)
	(segment
		(start 331.460602 -246.999506)
		(end 330.164948 -246.999506)
		(width 0.18288)
		(layer "In6.Cu")
		(net "M_D_CPU0_SB_CS_N<2>")
	)
	(segment
		(start 340.127082 -246.040148)
		(end 340.11235 -246.048784)
		(width 0.088646)
		(layer "In6.Cu")
		(net "M_D_CPU0_SB_CS_N<2>")
	)
	(segment
		(start 330.164948 -246.999506)
		(end 328.56932 -245.403878)
		(width 0.18288)
		(layer "In6.Cu")
		(net "M_D_CPU0_SB_CS_N<2>")
	)
	(segment
		(start 320.648838 -246.105426)
		(end 317.29553 -246.105426)
		(width 0.18288)
		(layer "In6.Cu")
		(net "M_D_CPU0_SB_CS_N<2>")
	)
	(segment
		(start 265.073384 -245.909084)
		(end 264.729214 -245.76659)
		(width 0.18288)
		(layer "In6.Cu")
		(net "M_D_CPU0_SB_CS_N<2>")
	)
	(segment
		(start 295.248838 -242.677442)
		(end 295.1353 -242.79098)
		(width 0.18288)
		(layer "In6.Cu")
		(net "M_D_CPU0_SB_CS_N<2>")
	)
	(segment
		(start 312.966862 -243.574824)
		(end 312.180986 -242.788948)
		(width 0.18288)
		(layer "In6.Cu")
		(net "M_D_CPU0_SB_CS_N<2>")
	)
	(segment
		(start 343.886282 -246.040148)
		(end 343.877392 -246.045228)
		(width 0.088646)
		(layer "In6.Cu")
		(net "M_D_CPU0_SB_CS_N<2>")
	)
	(segment
		(start 268.200886 -245.340886)
		(end 267.57376 -245.968012)
		(width 0.18288)
		(layer "In6.Cu")
		(net "M_D_CPU0_SB_CS_N<2>")
	)
	(segment
		(start 299.697394 -242.79098)
		(end 297.947842 -242.79098)
		(width 0.18288)
		(layer "In6.Cu")
		(net "M_D_CPU0_SB_CS_N<2>")
	)
	(segment
		(start 342.56853 -246.364506)
		(end 342.56853 -246.35587)
		(width 0.088646)
		(layer "In6.Cu")
		(net "M_D_CPU0_SB_CS_N<2>")
	)
	(segment
		(start 295.1353 -242.79098)
		(end 290.59378 -242.79098)
		(width 0.18288)
		(layer "In6.Cu")
		(net "M_D_CPU0_SB_CS_N<2>")
	)
	(segment
		(start 331.949552 -246.040148)
		(end 331.860906 -246.128794)
		(width 0.088646)
		(layer "In6.Cu")
		(net "M_D_CPU0_SB_CS_N<2>")
	)
	(segment
		(start 344.23096 -245.55069)
		(end 344.165174 -245.616476)
		(width 0.088646)
		(layer "In6.Cu")
		(net "M_D_CPU0_SB_CS_N<2>")
	)
	(segment
		(start 306.698904 -242.79098)
		(end 303.920906 -242.79098)
		(width 0.18288)
		(layer "In6.Cu")
		(net "M_D_CPU0_SB_CS_N<2>")
	)
	(segment
		(start 343.69883 -246.364506)
		(end 343.69883 -246.38)
		(width 0.088646)
		(layer "In6.Cu")
		(net "M_D_CPU0_SB_CS_N<2>")
	)
	(segment
		(start 270.483838 -245.203218)
		(end 270.34617 -245.340886)
		(width 0.18288)
		(layer "In6.Cu")
		(net "M_D_CPU0_SB_CS_N<2>")
	)
	(segment
		(start 297.834304 -242.677442)
		(end 295.248838 -242.677442)
		(width 0.18288)
		(layer "In6.Cu")
		(net "M_D_CPU0_SB_CS_N<2>")
	)
	(arc
		(start 338.621878 -246.040148)
		(mid 338.43468 -245.990005)
		(end 338.247482 -246.040148)
		(width 0.088646)
		(layer "In6.Cu")
		(net "M_D_CPU0_SB_CS_N<2>")
	)
	(arc
		(start 334.488536 -246.040148)
		(mid 334.205834 -246.115924)
		(end 333.923132 -246.040148)
		(width 0.088646)
		(layer "In6.Cu")
		(net "M_D_CPU0_SB_CS_N<2>")
	)
	(arc
		(start 344.165174 -245.616476)
		(mid 344.077886 -245.858432)
		(end 343.892378 -246.036592)
		(width 0.088646)
		(layer "In6.Cu")
		(net "M_D_CPU0_SB_CS_N<2>")
	)
	(arc
		(start 337.29295 -246.048784)
		(mid 337.016475 -246.116104)
		(end 336.742278 -246.040148)
		(width 0.088646)
		(layer "In6.Cu")
		(net "M_D_CPU0_SB_CS_N<2>")
	)
	(arc
		(start 341.441278 -246.040148)
		(mid 341.25408 -245.990005)
		(end 341.066882 -246.040148)
		(width 0.088646)
		(layer "In6.Cu")
		(net "M_D_CPU0_SB_CS_N<2>")
	)
	(arc
		(start 343.69883 -246.38)
		(mid 343.61946 -246.653734)
		(end 343.416636 -246.853964)
		(width 0.088646)
		(layer "In6.Cu")
		(net "M_D_CPU0_SB_CS_N<2>")
	)
	(arc
		(start 341.996522 -246.046244)
		(mid 341.71809 -246.11609)
		(end 341.441278 -246.040148)
		(width 0.088646)
		(layer "In6.Cu")
		(net "M_D_CPU0_SB_CS_N<2>")
	)
	(arc
		(start 339.187282 -246.040148)
		(mid 338.90458 -246.115924)
		(end 338.621878 -246.040148)
		(width 0.088646)
		(layer "In6.Cu")
		(net "M_D_CPU0_SB_CS_N<2>")
	)
	(arc
		(start 337.682078 -246.040148)
		(mid 337.49488 -245.990005)
		(end 337.307682 -246.040148)
		(width 0.088646)
		(layer "In6.Cu")
		(net "M_D_CPU0_SB_CS_N<2>")
	)
	(arc
		(start 339.561678 -246.040148)
		(mid 339.37448 -245.990005)
		(end 339.187282 -246.040148)
		(width 0.088646)
		(layer "In6.Cu")
		(net "M_D_CPU0_SB_CS_N<2>")
	)
	(arc
		(start 340.501478 -246.040148)
		(mid 340.31428 -245.990005)
		(end 340.127082 -246.040148)
		(width 0.088646)
		(layer "In6.Cu")
		(net "M_D_CPU0_SB_CS_N<2>")
	)
	(arc
		(start 332.608936 -246.040148)
		(mid 332.326234 -246.115924)
		(end 332.043532 -246.040148)
		(width 0.088646)
		(layer "In6.Cu")
		(net "M_D_CPU0_SB_CS_N<2>")
	)
	(arc
		(start 342.381332 -246.040148)
		(mid 342.194134 -245.990005)
		(end 342.006936 -246.040148)
		(width 0.088646)
		(layer "In6.Cu")
		(net "M_D_CPU0_SB_CS_N<2>")
	)
	(arc
		(start 336.357468 -246.046244)
		(mid 336.07929 -246.115967)
		(end 335.802732 -246.040148)
		(width 0.088646)
		(layer "In6.Cu")
		(net "M_D_CPU0_SB_CS_N<2>")
	)
	(arc
		(start 332.983332 -246.040148)
		(mid 332.796134 -245.990005)
		(end 332.608936 -246.040148)
		(width 0.088646)
		(layer "In6.Cu")
		(net "M_D_CPU0_SB_CS_N<2>")
	)
	(arc
		(start 340.11235 -246.048784)
		(mid 339.835875 -246.116104)
		(end 339.561678 -246.040148)
		(width 0.088646)
		(layer "In6.Cu")
		(net "M_D_CPU0_SB_CS_N<2>")
	)
	(arc
		(start 335.428336 -246.040148)
		(mid 335.145634 -246.115924)
		(end 334.862932 -246.040148)
		(width 0.088646)
		(layer "In6.Cu")
		(net "M_D_CPU0_SB_CS_N<2>")
	)
	(arc
		(start 334.862932 -246.040148)
		(mid 334.675734 -245.990005)
		(end 334.488536 -246.040148)
		(width 0.088646)
		(layer "In6.Cu")
		(net "M_D_CPU0_SB_CS_N<2>")
	)
	(arc
		(start 333.548736 -246.040148)
		(mid 333.266034 -246.115924)
		(end 332.983332 -246.040148)
		(width 0.088646)
		(layer "In6.Cu")
		(net "M_D_CPU0_SB_CS_N<2>")
	)
	(arc
		(start 342.845136 -246.850408)
		(mid 342.642549 -246.644057)
		(end 342.56853 -246.364506)
		(width 0.088646)
		(layer "In6.Cu")
		(net "M_D_CPU0_SB_CS_N<2>")
	)
	(arc
		(start 336.742278 -246.040148)
		(mid 336.55508 -245.990005)
		(end 336.367882 -246.040148)
		(width 0.088646)
		(layer "In6.Cu")
		(net "M_D_CPU0_SB_CS_N<2>")
	)
	(arc
		(start 343.416636 -246.853964)
		(mid 343.142437 -246.929799)
		(end 342.865964 -246.8626)
		(width 0.088646)
		(layer "In6.Cu")
		(net "M_D_CPU0_SB_CS_N<2>")
	)
	(arc
		(start 333.923132 -246.040148)
		(mid 333.735934 -245.990005)
		(end 333.548736 -246.040148)
		(width 0.088646)
		(layer "In6.Cu")
		(net "M_D_CPU0_SB_CS_N<2>")
	)
	(arc
		(start 342.56853 -246.35587)
		(mid 342.51626 -246.173505)
		(end 342.381332 -246.040148)
		(width 0.088646)
		(layer "In6.Cu")
		(net "M_D_CPU0_SB_CS_N<2>")
	)
	(arc
		(start 341.066882 -246.040148)
		(mid 340.78418 -246.115924)
		(end 340.501478 -246.040148)
		(width 0.088646)
		(layer "In6.Cu")
		(net "M_D_CPU0_SB_CS_N<2>")
	)
	(arc
		(start 343.877392 -246.045228)
		(mid 343.746478 -246.181588)
		(end 343.69883 -246.364506)
		(width 0.088646)
		(layer "In6.Cu")
		(net "M_D_CPU0_SB_CS_N<2>")
	)
	(arc
		(start 335.802732 -246.040148)
		(mid 335.615534 -245.990005)
		(end 335.428336 -246.040148)
		(width 0.088646)
		(layer "In6.Cu")
		(net "M_D_CPU0_SB_CS_N<2>")
	)
	(arc
		(start 338.23275 -246.048784)
		(mid 337.956275 -246.116104)
		(end 337.682078 -246.040148)
		(width 0.088646)
		(layer "In6.Cu")
		(net "M_D_CPU0_SB_CS_N<2>")
	)
	(segment
		(start 261.285482 -244.916706)
		(end 260.180582 -244.916706)
		(width 0.20066)
		(layer "F.Cu")
		(net "M_D_CPU0_SB_CS_N<1>")
	)
	(segment
		(start 345.01328 -246.900192)
		(end 345.01328 -246.364506)
		(width 0.20066)
		(layer "F.Cu")
		(net "M_D_CPU0_SB_CS_N<1>")
	)
	(segment
		(start 345.013534 -246.900446)
		(end 345.01328 -246.900192)
		(width 0.20066)
		(layer "F.Cu")
		(net "M_D_CPU0_SB_CS_N<1>")
	)
	(segment
		(start 263.132824 -241.090704)
		(end 261.800848 -242.42268)
		(width 0.18288)
		(layer "In6.Cu")
		(net "M_D_CPU0_SB_CS_N<1>")
	)
	(segment
		(start 271.94002 -239.63122)
		(end 270.480282 -241.090958)
		(width 0.18288)
		(layer "In6.Cu")
		(net "M_D_CPU0_SB_CS_N<1>")
	)
	(segment
		(start 275.458682 -239.390428)
		(end 275.458682 -240.134394)
		(width 0.18288)
		(layer "In6.Cu")
		(net "M_D_CPU0_SB_CS_N<1>")
	)
	(segment
		(start 274.767802 -239.390428)
		(end 274.584922 -239.207548)
		(width 0.18288)
		(layer "In6.Cu")
		(net "M_D_CPU0_SB_CS_N<1>")
	)
	(segment
		(start 303.746154 -240.382044)
		(end 303.007522 -239.643412)
		(width 0.18288)
		(layer "In6.Cu")
		(net "M_D_CPU0_SB_CS_N<1>")
	)
	(segment
		(start 285.298388 -240.058194)
		(end 285.298388 -239.58931)
		(width 0.18288)
		(layer "In6.Cu")
		(net "M_D_CPU0_SB_CS_N<1>")
	)
	(segment
		(start 335.428082 -245.060978)
		(end 335.41335 -245.052342)
		(width 0.088646)
		(layer "In6.Cu")
		(net "M_D_CPU0_SB_CS_N<1>")
	)
	(segment
		(start 331.949044 -245.060978)
		(end 331.353668 -245.656354)
		(width 0.088646)
		(layer "In6.Cu")
		(net "M_D_CPU0_SB_CS_N<1>")
	)
	(segment
		(start 284.607508 -239.58931)
		(end 284.607508 -240.058194)
		(width 0.18288)
		(layer "In6.Cu")
		(net "M_D_CPU0_SB_CS_N<1>")
	)
	(segment
		(start 340.127336 -245.060978)
		(end 340.116922 -245.054882)
		(width 0.088646)
		(layer "In6.Cu")
		(net "M_D_CPU0_SB_CS_N<1>")
	)
	(segment
		(start 311.207404 -240.244376)
		(end 307.336444 -240.244376)
		(width 0.18288)
		(layer "In6.Cu")
		(net "M_D_CPU0_SB_CS_N<1>")
	)
	(segment
		(start 284.790388 -239.40643)
		(end 284.607508 -239.58931)
		(width 0.18288)
		(layer "In6.Cu")
		(net "M_D_CPU0_SB_CS_N<1>")
	)
	(segment
		(start 331.353668 -245.783608)
		(end 331.265022 -245.872254)
		(width 0.088646)
		(layer "In6.Cu")
		(net "M_D_CPU0_SB_CS_N<1>")
	)
	(segment
		(start 261.800848 -244.114066)
		(end 261.597648 -244.60454)
		(width 0.18288)
		(layer "In6.Cu")
		(net "M_D_CPU0_SB_CS_N<1>")
	)
	(segment
		(start 303.007522 -239.643412)
		(end 300.345094 -239.643412)
		(width 0.18288)
		(layer "In6.Cu")
		(net "M_D_CPU0_SB_CS_N<1>")
	)
	(segment
		(start 298.926758 -240.24082)
		(end 298.925996 -240.241582)
		(width 0.18288)
		(layer "In6.Cu")
		(net "M_D_CPU0_SB_CS_N<1>")
	)
	(segment
		(start 261.800848 -242.42268)
		(end 261.800848 -244.114066)
		(width 0.18288)
		(layer "In6.Cu")
		(net "M_D_CPU0_SB_CS_N<1>")
	)
	(segment
		(start 278.109426 -240.241074)
		(end 277.0759 -239.207548)
		(width 0.18288)
		(layer "In6.Cu")
		(net "M_D_CPU0_SB_CS_N<1>")
	)
	(segment
		(start 300.345094 -239.643412)
		(end 299.747686 -240.24082)
		(width 0.18288)
		(layer "In6.Cu")
		(net "M_D_CPU0_SB_CS_N<1>")
	)
	(segment
		(start 336.367882 -245.060978)
		(end 336.35315 -245.052342)
		(width 0.088646)
		(layer "In6.Cu")
		(net "M_D_CPU0_SB_CS_N<1>")
	)
	(segment
		(start 277.0759 -239.207548)
		(end 275.641562 -239.207548)
		(width 0.18288)
		(layer "In6.Cu")
		(net "M_D_CPU0_SB_CS_N<1>")
	)
	(segment
		(start 274.950682 -240.317274)
		(end 274.767802 -240.134394)
		(width 0.18288)
		(layer "In6.Cu")
		(net "M_D_CPU0_SB_CS_N<1>")
	)
	(segment
		(start 295.930066 -240.241074)
		(end 285.481268 -240.241074)
		(width 0.18288)
		(layer "In6.Cu")
		(net "M_D_CPU0_SB_CS_N<1>")
	)
	(segment
		(start 311.4167 -240.453672)
		(end 311.207404 -240.244376)
		(width 0.18288)
		(layer "In6.Cu")
		(net "M_D_CPU0_SB_CS_N<1>")
	)
	(segment
		(start 265.267948 -241.090704)
		(end 263.132824 -241.090704)
		(width 0.18288)
		(layer "In6.Cu")
		(net "M_D_CPU0_SB_CS_N<1>")
	)
	(segment
		(start 333.548482 -245.060978)
		(end 333.53375 -245.052342)
		(width 0.088646)
		(layer "In6.Cu")
		(net "M_D_CPU0_SB_CS_N<1>")
	)
	(segment
		(start 295.930574 -240.241582)
		(end 295.930066 -240.241074)
		(width 0.18288)
		(layer "In6.Cu")
		(net "M_D_CPU0_SB_CS_N<1>")
	)
	(segment
		(start 312.324242 -240.453672)
		(end 311.4167 -240.453672)
		(width 0.18288)
		(layer "In6.Cu")
		(net "M_D_CPU0_SB_CS_N<1>")
	)
	(segment
		(start 275.458682 -240.134394)
		(end 275.275802 -240.317274)
		(width 0.18288)
		(layer "In6.Cu")
		(net "M_D_CPU0_SB_CS_N<1>")
	)
	(segment
		(start 337.307682 -245.060978)
		(end 337.29295 -245.052342)
		(width 0.088646)
		(layer "In6.Cu")
		(net "M_D_CPU0_SB_CS_N<1>")
	)
	(segment
		(start 273.478498 -239.207548)
		(end 273.054826 -239.63122)
		(width 0.18288)
		(layer "In6.Cu")
		(net "M_D_CPU0_SB_CS_N<1>")
	)
	(segment
		(start 328.983594 -244.387116)
		(end 317.790068 -244.387116)
		(width 0.18288)
		(layer "In6.Cu")
		(net "M_D_CPU0_SB_CS_N<1>")
	)
	(segment
		(start 342.946482 -245.060978)
		(end 342.93175 -245.052342)
		(width 0.088646)
		(layer "In6.Cu")
		(net "M_D_CPU0_SB_CS_N<1>")
	)
	(segment
		(start 274.584922 -239.207548)
		(end 273.478498 -239.207548)
		(width 0.18288)
		(layer "In6.Cu")
		(net "M_D_CPU0_SB_CS_N<1>")
	)
	(segment
		(start 285.481268 -240.241074)
		(end 285.298388 -240.058194)
		(width 0.18288)
		(layer "In6.Cu")
		(net "M_D_CPU0_SB_CS_N<1>")
	)
	(segment
		(start 332.608682 -245.060978)
		(end 332.59395 -245.052342)
		(width 0.088646)
		(layer "In6.Cu")
		(net "M_D_CPU0_SB_CS_N<1>")
	)
	(segment
		(start 273.054826 -239.63122)
		(end 271.94002 -239.63122)
		(width 0.18288)
		(layer "In6.Cu")
		(net "M_D_CPU0_SB_CS_N<1>")
	)
	(segment
		(start 285.298388 -239.58931)
		(end 285.115508 -239.40643)
		(width 0.18288)
		(layer "In6.Cu")
		(net "M_D_CPU0_SB_CS_N<1>")
	)
	(segment
		(start 334.488282 -245.060978)
		(end 334.47355 -245.052342)
		(width 0.088646)
		(layer "In6.Cu")
		(net "M_D_CPU0_SB_CS_N<1>")
	)
	(segment
		(start 307.198776 -240.382044)
		(end 303.746154 -240.382044)
		(width 0.18288)
		(layer "In6.Cu")
		(net "M_D_CPU0_SB_CS_N<1>")
	)
	(segment
		(start 317.790068 -244.387116)
		(end 315.371226 -241.968274)
		(width 0.18288)
		(layer "In6.Cu")
		(net "M_D_CPU0_SB_CS_N<1>")
	)
	(segment
		(start 275.275802 -240.317274)
		(end 274.950682 -240.317274)
		(width 0.18288)
		(layer "In6.Cu")
		(net "M_D_CPU0_SB_CS_N<1>")
	)
	(segment
		(start 331.131164 -245.872254)
		(end 330.468732 -245.872254)
		(width 0.18288)
		(layer "In6.Cu")
		(net "M_D_CPU0_SB_CS_N<1>")
	)
	(segment
		(start 338.632546 -245.054882)
		(end 338.622132 -245.060978)
		(width 0.088646)
		(layer "In6.Cu")
		(net "M_D_CPU0_SB_CS_N<1>")
	)
	(segment
		(start 261.597648 -244.60454)
		(end 261.285482 -244.916706)
		(width 0.18288)
		(layer "In6.Cu")
		(net "M_D_CPU0_SB_CS_N<1>")
	)
	(segment
		(start 285.115508 -239.40643)
		(end 284.790388 -239.40643)
		(width 0.18288)
		(layer "In6.Cu")
		(net "M_D_CPU0_SB_CS_N<1>")
	)
	(segment
		(start 298.925996 -240.241582)
		(end 295.930574 -240.241582)
		(width 0.18288)
		(layer "In6.Cu")
		(net "M_D_CPU0_SB_CS_N<1>")
	)
	(segment
		(start 284.424628 -240.241074)
		(end 278.109426 -240.241074)
		(width 0.18288)
		(layer "In6.Cu")
		(net "M_D_CPU0_SB_CS_N<1>")
	)
	(segment
		(start 299.747686 -240.24082)
		(end 298.926758 -240.24082)
		(width 0.18288)
		(layer "In6.Cu")
		(net "M_D_CPU0_SB_CS_N<1>")
	)
	(segment
		(start 274.767802 -240.134394)
		(end 274.767802 -239.390428)
		(width 0.18288)
		(layer "In6.Cu")
		(net "M_D_CPU0_SB_CS_N<1>")
	)
	(segment
		(start 330.468732 -245.872254)
		(end 328.983594 -244.387116)
		(width 0.18288)
		(layer "In6.Cu")
		(net "M_D_CPU0_SB_CS_N<1>")
	)
	(segment
		(start 307.336444 -240.244376)
		(end 307.198776 -240.382044)
		(width 0.18288)
		(layer "In6.Cu")
		(net "M_D_CPU0_SB_CS_N<1>")
	)
	(segment
		(start 342.006682 -245.060978)
		(end 341.99195 -245.052342)
		(width 0.088646)
		(layer "In6.Cu")
		(net "M_D_CPU0_SB_CS_N<1>")
	)
	(segment
		(start 265.268202 -241.090958)
		(end 265.267948 -241.090704)
		(width 0.18288)
		(layer "In6.Cu")
		(net "M_D_CPU0_SB_CS_N<1>")
	)
	(segment
		(start 331.353668 -245.656354)
		(end 331.353668 -245.783608)
		(width 0.088646)
		(layer "In6.Cu")
		(net "M_D_CPU0_SB_CS_N<1>")
	)
	(segment
		(start 332.043278 -245.060978)
		(end 331.949044 -245.060978)
		(width 0.088646)
		(layer "In6.Cu")
		(net "M_D_CPU0_SB_CS_N<1>")
	)
	(segment
		(start 284.607508 -240.058194)
		(end 284.424628 -240.241074)
		(width 0.18288)
		(layer "In6.Cu")
		(net "M_D_CPU0_SB_CS_N<1>")
	)
	(segment
		(start 275.641562 -239.207548)
		(end 275.458682 -239.390428)
		(width 0.18288)
		(layer "In6.Cu")
		(net "M_D_CPU0_SB_CS_N<1>")
	)
	(segment
		(start 331.265022 -245.872254)
		(end 331.131164 -245.872254)
		(width 0.088646)
		(layer "In6.Cu")
		(net "M_D_CPU0_SB_CS_N<1>")
	)
	(segment
		(start 315.371226 -241.968274)
		(end 313.838844 -241.968274)
		(width 0.18288)
		(layer "In6.Cu")
		(net "M_D_CPU0_SB_CS_N<1>")
	)
	(segment
		(start 340.512146 -245.054882)
		(end 340.501732 -245.060978)
		(width 0.088646)
		(layer "In6.Cu")
		(net "M_D_CPU0_SB_CS_N<1>")
	)
	(segment
		(start 338.247736 -245.060978)
		(end 338.237322 -245.054882)
		(width 0.088646)
		(layer "In6.Cu")
		(net "M_D_CPU0_SB_CS_N<1>")
	)
	(segment
		(start 313.838844 -241.968274)
		(end 312.324242 -240.453672)
		(width 0.18288)
		(layer "In6.Cu")
		(net "M_D_CPU0_SB_CS_N<1>")
	)
	(segment
		(start 270.480282 -241.090958)
		(end 265.268202 -241.090958)
		(width 0.18288)
		(layer "In6.Cu")
		(net "M_D_CPU0_SB_CS_N<1>")
	)
	(arc
		(start 341.99195 -245.052342)
		(mid 341.715509 -244.985176)
		(end 341.441278 -245.060978)
		(width 0.088646)
		(layer "In6.Cu")
		(net "M_D_CPU0_SB_CS_N<1>")
	)
	(arc
		(start 339.561678 -245.060978)
		(mid 339.37448 -245.111121)
		(end 339.187282 -245.060978)
		(width 0.088646)
		(layer "In6.Cu")
		(net "M_D_CPU0_SB_CS_N<1>")
	)
	(arc
		(start 342.381078 -245.060978)
		(mid 342.19388 -245.111121)
		(end 342.006682 -245.060978)
		(width 0.088646)
		(layer "In6.Cu")
		(net "M_D_CPU0_SB_CS_N<1>")
	)
	(arc
		(start 336.35315 -245.052342)
		(mid 336.076709 -244.985176)
		(end 335.802478 -245.060978)
		(width 0.088646)
		(layer "In6.Cu")
		(net "M_D_CPU0_SB_CS_N<1>")
	)
	(arc
		(start 344.499184 -245.130574)
		(mid 344.411717 -245.123015)
		(end 344.323924 -245.122954)
		(width 0.088646)
		(layer "In6.Cu")
		(net "M_D_CPU0_SB_CS_N<1>")
	)
	(arc
		(start 335.41335 -245.052342)
		(mid 335.136909 -244.985176)
		(end 334.862678 -245.060978)
		(width 0.088646)
		(layer "In6.Cu")
		(net "M_D_CPU0_SB_CS_N<1>")
	)
	(arc
		(start 337.29295 -245.052342)
		(mid 337.016509 -244.985176)
		(end 336.742278 -245.060978)
		(width 0.088646)
		(layer "In6.Cu")
		(net "M_D_CPU0_SB_CS_N<1>")
	)
	(arc
		(start 344.323924 -245.122954)
		(mid 344.226589 -245.122941)
		(end 344.129614 -245.114572)
		(width 0.088646)
		(layer "In6.Cu")
		(net "M_D_CPU0_SB_CS_N<1>")
	)
	(arc
		(start 344.077544 -245.11127)
		(mid 343.977679 -245.098837)
		(end 343.884758 -245.060216)
		(width 0.088646)
		(layer "In6.Cu")
		(net "M_D_CPU0_SB_CS_N<1>")
	)
	(arc
		(start 340.501732 -245.060978)
		(mid 340.314534 -245.111121)
		(end 340.127336 -245.060978)
		(width 0.088646)
		(layer "In6.Cu")
		(net "M_D_CPU0_SB_CS_N<1>")
	)
	(arc
		(start 336.742278 -245.060978)
		(mid 336.55508 -245.111121)
		(end 336.367882 -245.060978)
		(width 0.088646)
		(layer "In6.Cu")
		(net "M_D_CPU0_SB_CS_N<1>")
	)
	(arc
		(start 345.01328 -246.364506)
		(mid 345.004233 -245.97856)
		(end 344.96629 -245.594378)
		(width 0.088646)
		(layer "In6.Cu")
		(net "M_D_CPU0_SB_CS_N<1>")
	)
	(arc
		(start 341.066882 -245.060978)
		(mid 340.790323 -244.985269)
		(end 340.512146 -245.054882)
		(width 0.088646)
		(layer "In6.Cu")
		(net "M_D_CPU0_SB_CS_N<1>")
	)
	(arc
		(start 333.53375 -245.052342)
		(mid 333.257309 -244.985176)
		(end 332.983078 -245.060978)
		(width 0.088646)
		(layer "In6.Cu")
		(net "M_D_CPU0_SB_CS_N<1>")
	)
	(arc
		(start 340.116922 -245.054882)
		(mid 339.83849 -244.985068)
		(end 339.561678 -245.060978)
		(width 0.088646)
		(layer "In6.Cu")
		(net "M_D_CPU0_SB_CS_N<1>")
	)
	(arc
		(start 341.441278 -245.060978)
		(mid 341.25408 -245.111121)
		(end 341.066882 -245.060978)
		(width 0.088646)
		(layer "In6.Cu")
		(net "M_D_CPU0_SB_CS_N<1>")
	)
	(arc
		(start 342.93175 -245.052342)
		(mid 342.655309 -244.985176)
		(end 342.381078 -245.060978)
		(width 0.088646)
		(layer "In6.Cu")
		(net "M_D_CPU0_SB_CS_N<1>")
	)
	(arc
		(start 334.47355 -245.052342)
		(mid 334.197109 -244.985176)
		(end 333.922878 -245.060978)
		(width 0.088646)
		(layer "In6.Cu")
		(net "M_D_CPU0_SB_CS_N<1>")
	)
	(arc
		(start 335.802478 -245.060978)
		(mid 335.61528 -245.111121)
		(end 335.428082 -245.060978)
		(width 0.088646)
		(layer "In6.Cu")
		(net "M_D_CPU0_SB_CS_N<1>")
	)
	(arc
		(start 337.682078 -245.060978)
		(mid 337.49488 -245.111121)
		(end 337.307682 -245.060978)
		(width 0.088646)
		(layer "In6.Cu")
		(net "M_D_CPU0_SB_CS_N<1>")
	)
	(arc
		(start 339.187282 -245.060978)
		(mid 338.910723 -244.985269)
		(end 338.632546 -245.054882)
		(width 0.088646)
		(layer "In6.Cu")
		(net "M_D_CPU0_SB_CS_N<1>")
	)
	(arc
		(start 338.622132 -245.060978)
		(mid 338.434934 -245.111121)
		(end 338.247736 -245.060978)
		(width 0.088646)
		(layer "In6.Cu")
		(net "M_D_CPU0_SB_CS_N<1>")
	)
	(arc
		(start 343.320878 -245.060978)
		(mid 343.13368 -245.111121)
		(end 342.946482 -245.060978)
		(width 0.088646)
		(layer "In6.Cu")
		(net "M_D_CPU0_SB_CS_N<1>")
	)
	(arc
		(start 338.237322 -245.054882)
		(mid 337.95889 -244.985068)
		(end 337.682078 -245.060978)
		(width 0.088646)
		(layer "In6.Cu")
		(net "M_D_CPU0_SB_CS_N<1>")
	)
	(arc
		(start 333.922878 -245.060978)
		(mid 333.73568 -245.111121)
		(end 333.548482 -245.060978)
		(width 0.088646)
		(layer "In6.Cu")
		(net "M_D_CPU0_SB_CS_N<1>")
	)
	(arc
		(start 332.59395 -245.052342)
		(mid 332.317509 -244.985176)
		(end 332.043278 -245.060978)
		(width 0.088646)
		(layer "In6.Cu")
		(net "M_D_CPU0_SB_CS_N<1>")
	)
	(arc
		(start 332.983078 -245.060978)
		(mid 332.79588 -245.111121)
		(end 332.608682 -245.060978)
		(width 0.088646)
		(layer "In6.Cu")
		(net "M_D_CPU0_SB_CS_N<1>")
	)
	(arc
		(start 334.862678 -245.060978)
		(mid 334.67548 -245.111121)
		(end 334.488282 -245.060978)
		(width 0.088646)
		(layer "In6.Cu")
		(net "M_D_CPU0_SB_CS_N<1>")
	)
	(arc
		(start 344.129614 -245.114572)
		(mid 344.103637 -245.112005)
		(end 344.077544 -245.11127)
		(width 0.088646)
		(layer "In6.Cu")
		(net "M_D_CPU0_SB_CS_N<1>")
	)
	(arc
		(start 343.804748 -245.021608)
		(mid 343.558387 -244.986778)
		(end 343.320878 -245.060978)
		(width 0.088646)
		(layer "In6.Cu")
		(net "M_D_CPU0_SB_CS_N<1>")
	)
	(arc
		(start 343.884758 -245.060216)
		(mid 343.845553 -245.039254)
		(end 343.804748 -245.021608)
		(width 0.088646)
		(layer "In6.Cu")
		(net "M_D_CPU0_SB_CS_N<1>")
	)
	(arc
		(start 344.96629 -245.594378)
		(mid 344.811265 -245.283389)
		(end 344.499184 -245.130574)
		(width 0.088646)
		(layer "In6.Cu")
		(net "M_D_CPU0_SB_CS_N<1>")
	)
	(segment
		(start 257.185414 -245.76659)
		(end 256.080514 -245.76659)
		(width 0.20066)
		(layer "F.Cu")
		(net "M_D_CPU0_SB_CS_N<0>")
	)
	(segment
		(start 343.133934 -246.900446)
		(end 343.13368 -246.900192)
		(width 0.20066)
		(layer "F.Cu")
		(net "M_D_CPU0_SB_CS_N<0>")
	)
	(segment
		(start 343.13368 -246.900192)
		(end 343.13368 -246.364506)
		(width 0.20066)
		(layer "F.Cu")
		(net "M_D_CPU0_SB_CS_N<0>")
	)
	(segment
		(start 272.773902 -240.16208)
		(end 272.1229 -240.16208)
		(width 0.18288)
		(layer "In6.Cu")
		(net "M_D_CPU0_SB_CS_N<0>")
	)
	(segment
		(start 340.596982 -245.226332)
		(end 340.586568 -245.232428)
		(width 0.088646)
		(layer "In6.Cu")
		(net "M_D_CPU0_SB_CS_N<0>")
	)
	(segment
		(start 336.287364 -245.234968)
		(end 336.272632 -245.226332)
		(width 0.088646)
		(layer "In6.Cu")
		(net "M_D_CPU0_SB_CS_N<0>")
	)
	(segment
		(start 315.17463 -242.499134)
		(end 313.63666 -242.499134)
		(width 0.18288)
		(layer "In6.Cu")
		(net "M_D_CPU0_SB_CS_N<0>")
	)
	(segment
		(start 320.519298 -245.01602)
		(end 317.691516 -245.01602)
		(width 0.18288)
		(layer "In6.Cu")
		(net "M_D_CPU0_SB_CS_N<0>")
	)
	(segment
		(start 312.227976 -241.09045)
		(end 310.819038 -241.09045)
		(width 0.18288)
		(layer "In6.Cu")
		(net "M_D_CPU0_SB_CS_N<0>")
	)
	(segment
		(start 313.63666 -242.499134)
		(end 312.227976 -241.09045)
		(width 0.18288)
		(layer "In6.Cu")
		(net "M_D_CPU0_SB_CS_N<0>")
	)
	(segment
		(start 331.343762 -246.21998)
		(end 331.131418 -246.21998)
		(width 0.088646)
		(layer "In6.Cu")
		(net "M_D_CPU0_SB_CS_N<0>")
	)
	(segment
		(start 332.112112 -245.253256)
		(end 332.035912 -245.253256)
		(width 0.088646)
		(layer "In6.Cu")
		(net "M_D_CPU0_SB_CS_N<0>")
	)
	(segment
		(start 261.6581 -245.34495)
		(end 260.601206 -245.34495)
		(width 0.18288)
		(layer "In6.Cu")
		(net "M_D_CPU0_SB_CS_N<0>")
	)
	(segment
		(start 339.102192 -245.232428)
		(end 339.091778 -245.226332)
		(width 0.088646)
		(layer "In6.Cu")
		(net "M_D_CPU0_SB_CS_N<0>")
	)
	(segment
		(start 259.699506 -245.52783)
		(end 259.516626 -245.34495)
		(width 0.18288)
		(layer "In6.Cu")
		(net "M_D_CPU0_SB_CS_N<0>")
	)
	(segment
		(start 258.39928 -245.76659)
		(end 257.185414 -245.76659)
		(width 0.18288)
		(layer "In6.Cu")
		(net "M_D_CPU0_SB_CS_N<0>")
	)
	(segment
		(start 262.918448 -243.870226)
		(end 262.137652 -244.651022)
		(width 0.18288)
		(layer "In6.Cu")
		(net "M_D_CPU0_SB_CS_N<0>")
	)
	(segment
		(start 332.035912 -245.253256)
		(end 331.548994 -245.740174)
		(width 0.088646)
		(layer "In6.Cu")
		(net "M_D_CPU0_SB_CS_N<0>")
	)
	(segment
		(start 310.819038 -241.09045)
		(end 310.706262 -241.203226)
		(width 0.18288)
		(layer "In6.Cu")
		(net "M_D_CPU0_SB_CS_N<0>")
	)
	(segment
		(start 335.347564 -245.234968)
		(end 335.332832 -245.226332)
		(width 0.088646)
		(layer "In6.Cu")
		(net "M_D_CPU0_SB_CS_N<0>")
	)
	(segment
		(start 262.137652 -244.651022)
		(end 261.986014 -245.017036)
		(width 0.18288)
		(layer "In6.Cu")
		(net "M_D_CPU0_SB_CS_N<0>")
	)
	(segment
		(start 259.699506 -246.03075)
		(end 259.699506 -245.52783)
		(width 0.18288)
		(layer "In6.Cu")
		(net "M_D_CPU0_SB_CS_N<0>")
	)
	(segment
		(start 332.528164 -245.234968)
		(end 332.513432 -245.226332)
		(width 0.088646)
		(layer "In6.Cu")
		(net "M_D_CPU0_SB_CS_N<0>")
	)
	(segment
		(start 273.47037 -240.858548)
		(end 272.773902 -240.16208)
		(width 0.18288)
		(layer "In6.Cu")
		(net "M_D_CPU0_SB_CS_N<0>")
	)
	(segment
		(start 259.516626 -245.34495)
		(end 258.82092 -245.34495)
		(width 0.18288)
		(layer "In6.Cu")
		(net "M_D_CPU0_SB_CS_N<0>")
	)
	(segment
		(start 331.131418 -246.21998)
		(end 330.334874 -246.21998)
		(width 0.18288)
		(layer "In6.Cu")
		(net "M_D_CPU0_SB_CS_N<0>")
	)
	(segment
		(start 333.467964 -245.234968)
		(end 333.453232 -245.226332)
		(width 0.088646)
		(layer "In6.Cu")
		(net "M_D_CPU0_SB_CS_N<0>")
	)
	(segment
		(start 258.82092 -245.34495)
		(end 258.39928 -245.76659)
		(width 0.18288)
		(layer "In6.Cu")
		(net "M_D_CPU0_SB_CS_N<0>")
	)
	(segment
		(start 306.870354 -241.000026)
		(end 303.650904 -241.000026)
		(width 0.18288)
		(layer "In6.Cu")
		(net "M_D_CPU0_SB_CS_N<0>")
	)
	(segment
		(start 330.334874 -246.21998)
		(end 328.840592 -244.725698)
		(width 0.18288)
		(layer "In6.Cu")
		(net "M_D_CPU0_SB_CS_N<0>")
	)
	(segment
		(start 341.926164 -245.234968)
		(end 341.911432 -245.226332)
		(width 0.088646)
		(layer "In6.Cu")
		(net "M_D_CPU0_SB_CS_N<0>")
	)
	(segment
		(start 261.986014 -245.017036)
		(end 261.6581 -245.34495)
		(width 0.18288)
		(layer "In6.Cu")
		(net "M_D_CPU0_SB_CS_N<0>")
	)
	(segment
		(start 307.073554 -241.203226)
		(end 306.870354 -241.000026)
		(width 0.18288)
		(layer "In6.Cu")
		(net "M_D_CPU0_SB_CS_N<0>")
	)
	(segment
		(start 340.981792 -245.232428)
		(end 340.971378 -245.226332)
		(width 0.088646)
		(layer "In6.Cu")
		(net "M_D_CPU0_SB_CS_N<0>")
	)
	(segment
		(start 342.865964 -245.234968)
		(end 342.851232 -245.226332)
		(width 0.088646)
		(layer "In6.Cu")
		(net "M_D_CPU0_SB_CS_N<0>")
	)
	(segment
		(start 270.344138 -241.940842)
		(end 264.009886 -241.940842)
		(width 0.18288)
		(layer "In6.Cu")
		(net "M_D_CPU0_SB_CS_N<0>")
	)
	(segment
		(start 310.706262 -241.203226)
		(end 307.073554 -241.203226)
		(width 0.18288)
		(layer "In6.Cu")
		(net "M_D_CPU0_SB_CS_N<0>")
	)
	(segment
		(start 260.601206 -245.34495)
		(end 260.418326 -245.52783)
		(width 0.18288)
		(layer "In6.Cu")
		(net "M_D_CPU0_SB_CS_N<0>")
	)
	(segment
		(start 320.80962 -244.725698)
		(end 320.519298 -245.01602)
		(width 0.18288)
		(layer "In6.Cu")
		(net "M_D_CPU0_SB_CS_N<0>")
	)
	(segment
		(start 332.139036 -245.226332)
		(end 332.112112 -245.253256)
		(width 0.088646)
		(layer "In6.Cu")
		(net "M_D_CPU0_SB_CS_N<0>")
	)
	(segment
		(start 259.882386 -246.21363)
		(end 259.699506 -246.03075)
		(width 0.18288)
		(layer "In6.Cu")
		(net "M_D_CPU0_SB_CS_N<0>")
	)
	(segment
		(start 328.840592 -244.725698)
		(end 320.80962 -244.725698)
		(width 0.18288)
		(layer "In6.Cu")
		(net "M_D_CPU0_SB_CS_N<0>")
	)
	(segment
		(start 303.650904 -241.000026)
		(end 302.79848 -240.147602)
		(width 0.18288)
		(layer "In6.Cu")
		(net "M_D_CPU0_SB_CS_N<0>")
	)
	(segment
		(start 260.235446 -246.21363)
		(end 259.882386 -246.21363)
		(width 0.18288)
		(layer "In6.Cu")
		(net "M_D_CPU0_SB_CS_N<0>")
	)
	(segment
		(start 301.81931 -240.147602)
		(end 300.875954 -241.090958)
		(width 0.18288)
		(layer "In6.Cu")
		(net "M_D_CPU0_SB_CS_N<0>")
	)
	(segment
		(start 276.82698 -240.858548)
		(end 273.47037 -240.858548)
		(width 0.18288)
		(layer "In6.Cu")
		(net "M_D_CPU0_SB_CS_N<0>")
	)
	(segment
		(start 334.407764 -245.234968)
		(end 334.393032 -245.226332)
		(width 0.088646)
		(layer "In6.Cu")
		(net "M_D_CPU0_SB_CS_N<0>")
	)
	(segment
		(start 338.717382 -245.226332)
		(end 338.706968 -245.232428)
		(width 0.088646)
		(layer "In6.Cu")
		(net "M_D_CPU0_SB_CS_N<0>")
	)
	(segment
		(start 331.548994 -245.83136)
		(end 331.4192 -246.144542)
		(width 0.088646)
		(layer "In6.Cu")
		(net "M_D_CPU0_SB_CS_N<0>")
	)
	(segment
		(start 302.79848 -240.147602)
		(end 301.81931 -240.147602)
		(width 0.18288)
		(layer "In6.Cu")
		(net "M_D_CPU0_SB_CS_N<0>")
	)
	(segment
		(start 331.4192 -246.144542)
		(end 331.343762 -246.21998)
		(width 0.088646)
		(layer "In6.Cu")
		(net "M_D_CPU0_SB_CS_N<0>")
	)
	(segment
		(start 264.009886 -241.940842)
		(end 262.918448 -243.03228)
		(width 0.18288)
		(layer "In6.Cu")
		(net "M_D_CPU0_SB_CS_N<0>")
	)
	(segment
		(start 277.05939 -241.090958)
		(end 276.82698 -240.858548)
		(width 0.18288)
		(layer "In6.Cu")
		(net "M_D_CPU0_SB_CS_N<0>")
	)
	(segment
		(start 260.418326 -245.52783)
		(end 260.418326 -246.03075)
		(width 0.18288)
		(layer "In6.Cu")
		(net "M_D_CPU0_SB_CS_N<0>")
	)
	(segment
		(start 272.1229 -240.16208)
		(end 270.344138 -241.940842)
		(width 0.18288)
		(layer "In6.Cu")
		(net "M_D_CPU0_SB_CS_N<0>")
	)
	(segment
		(start 260.418326 -246.03075)
		(end 260.235446 -246.21363)
		(width 0.18288)
		(layer "In6.Cu")
		(net "M_D_CPU0_SB_CS_N<0>")
	)
	(segment
		(start 317.691516 -245.01602)
		(end 315.17463 -242.499134)
		(width 0.18288)
		(layer "In6.Cu")
		(net "M_D_CPU0_SB_CS_N<0>")
	)
	(segment
		(start 300.875954 -241.090958)
		(end 277.05939 -241.090958)
		(width 0.18288)
		(layer "In6.Cu")
		(net "M_D_CPU0_SB_CS_N<0>")
	)
	(segment
		(start 262.918448 -243.03228)
		(end 262.918448 -243.870226)
		(width 0.18288)
		(layer "In6.Cu")
		(net "M_D_CPU0_SB_CS_N<0>")
	)
	(segment
		(start 331.548994 -245.740174)
		(end 331.548994 -245.83136)
		(width 0.088646)
		(layer "In6.Cu")
		(net "M_D_CPU0_SB_CS_N<0>")
	)
	(segment
		(start 337.227164 -245.234968)
		(end 337.212432 -245.226332)
		(width 0.088646)
		(layer "In6.Cu")
		(net "M_D_CPU0_SB_CS_N<0>")
	)
	(arc
		(start 340.586568 -245.232428)
		(mid 340.30839 -245.30212)
		(end 340.031832 -245.226332)
		(width 0.088646)
		(layer "In6.Cu")
		(net "M_D_CPU0_SB_CS_N<0>")
	)
	(arc
		(start 342.476836 -245.226332)
		(mid 342.202607 -245.302257)
		(end 341.926164 -245.234968)
		(width 0.088646)
		(layer "In6.Cu")
		(net "M_D_CPU0_SB_CS_N<0>")
	)
	(arc
		(start 343.13368 -246.364506)
		(mid 343.171251 -245.859238)
		(end 343.054178 -245.366286)
		(width 0.088646)
		(layer "In6.Cu")
		(net "M_D_CPU0_SB_CS_N<0>")
	)
	(arc
		(start 336.272632 -245.226332)
		(mid 336.085434 -245.176189)
		(end 335.898236 -245.226332)
		(width 0.088646)
		(layer "In6.Cu")
		(net "M_D_CPU0_SB_CS_N<0>")
	)
	(arc
		(start 339.657436 -245.226332)
		(mid 339.380623 -245.302168)
		(end 339.102192 -245.232428)
		(width 0.088646)
		(layer "In6.Cu")
		(net "M_D_CPU0_SB_CS_N<0>")
	)
	(arc
		(start 343.054178 -245.366286)
		(mid 343.014719 -245.308892)
		(end 342.954864 -245.273322)
		(width 0.088646)
		(layer "In6.Cu")
		(net "M_D_CPU0_SB_CS_N<0>")
	)
	(arc
		(start 338.706968 -245.232428)
		(mid 338.42879 -245.30212)
		(end 338.152232 -245.226332)
		(width 0.088646)
		(layer "In6.Cu")
		(net "M_D_CPU0_SB_CS_N<0>")
	)
	(arc
		(start 332.513432 -245.226332)
		(mid 332.326234 -245.176189)
		(end 332.139036 -245.226332)
		(width 0.088646)
		(layer "In6.Cu")
		(net "M_D_CPU0_SB_CS_N<0>")
	)
	(arc
		(start 334.958436 -245.226332)
		(mid 334.684207 -245.302257)
		(end 334.407764 -245.234968)
		(width 0.088646)
		(layer "In6.Cu")
		(net "M_D_CPU0_SB_CS_N<0>")
	)
	(arc
		(start 337.777836 -245.226332)
		(mid 337.503607 -245.302257)
		(end 337.227164 -245.234968)
		(width 0.088646)
		(layer "In6.Cu")
		(net "M_D_CPU0_SB_CS_N<0>")
	)
	(arc
		(start 337.212432 -245.226332)
		(mid 337.025234 -245.176189)
		(end 336.838036 -245.226332)
		(width 0.088646)
		(layer "In6.Cu")
		(net "M_D_CPU0_SB_CS_N<0>")
	)
	(arc
		(start 335.898236 -245.226332)
		(mid 335.624007 -245.302257)
		(end 335.347564 -245.234968)
		(width 0.088646)
		(layer "In6.Cu")
		(net "M_D_CPU0_SB_CS_N<0>")
	)
	(arc
		(start 342.851232 -245.226332)
		(mid 342.664034 -245.176189)
		(end 342.476836 -245.226332)
		(width 0.088646)
		(layer "In6.Cu")
		(net "M_D_CPU0_SB_CS_N<0>")
	)
	(arc
		(start 333.078836 -245.226332)
		(mid 332.804607 -245.302257)
		(end 332.528164 -245.234968)
		(width 0.088646)
		(layer "In6.Cu")
		(net "M_D_CPU0_SB_CS_N<0>")
	)
	(arc
		(start 334.018636 -245.226332)
		(mid 333.744407 -245.302257)
		(end 333.467964 -245.234968)
		(width 0.088646)
		(layer "In6.Cu")
		(net "M_D_CPU0_SB_CS_N<0>")
	)
	(arc
		(start 333.453232 -245.226332)
		(mid 333.266034 -245.176189)
		(end 333.078836 -245.226332)
		(width 0.088646)
		(layer "In6.Cu")
		(net "M_D_CPU0_SB_CS_N<0>")
	)
	(arc
		(start 334.393032 -245.226332)
		(mid 334.205834 -245.176189)
		(end 334.018636 -245.226332)
		(width 0.088646)
		(layer "In6.Cu")
		(net "M_D_CPU0_SB_CS_N<0>")
	)
	(arc
		(start 342.954864 -245.273322)
		(mid 342.909592 -245.256051)
		(end 342.865964 -245.234968)
		(width 0.088646)
		(layer "In6.Cu")
		(net "M_D_CPU0_SB_CS_N<0>")
	)
	(arc
		(start 340.031832 -245.226332)
		(mid 339.844634 -245.176189)
		(end 339.657436 -245.226332)
		(width 0.088646)
		(layer "In6.Cu")
		(net "M_D_CPU0_SB_CS_N<0>")
	)
	(arc
		(start 340.971378 -245.226332)
		(mid 340.78418 -245.176189)
		(end 340.596982 -245.226332)
		(width 0.088646)
		(layer "In6.Cu")
		(net "M_D_CPU0_SB_CS_N<0>")
	)
	(arc
		(start 339.091778 -245.226332)
		(mid 338.90458 -245.176189)
		(end 338.717382 -245.226332)
		(width 0.088646)
		(layer "In6.Cu")
		(net "M_D_CPU0_SB_CS_N<0>")
	)
	(arc
		(start 341.911432 -245.226332)
		(mid 341.724234 -245.176189)
		(end 341.537036 -245.226332)
		(width 0.088646)
		(layer "In6.Cu")
		(net "M_D_CPU0_SB_CS_N<0>")
	)
	(arc
		(start 338.152232 -245.226332)
		(mid 337.965034 -245.176189)
		(end 337.777836 -245.226332)
		(width 0.088646)
		(layer "In6.Cu")
		(net "M_D_CPU0_SB_CS_N<0>")
	)
	(arc
		(start 335.332832 -245.226332)
		(mid 335.145634 -245.176189)
		(end 334.958436 -245.226332)
		(width 0.088646)
		(layer "In6.Cu")
		(net "M_D_CPU0_SB_CS_N<0>")
	)
	(arc
		(start 341.537036 -245.226332)
		(mid 341.260223 -245.302168)
		(end 340.981792 -245.232428)
		(width 0.088646)
		(layer "In6.Cu")
		(net "M_D_CPU0_SB_CS_N<0>")
	)
	(arc
		(start 336.838036 -245.226332)
		(mid 336.563807 -245.302257)
		(end 336.287364 -245.234968)
		(width 0.088646)
		(layer "In6.Cu")
		(net "M_D_CPU0_SB_CS_N<0>")
	)
	(segment
		(start 262.752332 -239.391698)
		(end 262.514334 -239.391698)
		(width 0.101854)
		(layer "F.Cu")
		(net "M_D_CPU0_SB_CB<7>")
	)
	(segment
		(start 348.302834 -246.086376)
		(end 348.302834 -245.55069)
		(width 0.20066)
		(layer "F.Cu")
		(net "M_D_CPU0_SB_CB<7>")
	)
	(segment
		(start 266.25423 -239.174274)
		(end 266.042394 -238.962438)
		(width 0.20066)
		(layer "F.Cu")
		(net "M_D_CPU0_SB_CB<7>")
	)
	(segment
		(start 267.724382 -238.966756)
		(end 266.90828 -238.966756)
		(width 0.20066)
		(layer "F.Cu")
		(net "M_D_CPU0_SB_CB<7>")
	)
	(segment
		(start 262.514334 -239.391698)
		(end 262.50011 -239.405922)
		(width 0.101854)
		(layer "F.Cu")
		(net "M_D_CPU0_SB_CB<7>")
	)
	(segment
		(start 265.518646 -239.2426)
		(end 265.369548 -239.391698)
		(width 0.20066)
		(layer "F.Cu")
		(net "M_D_CPU0_SB_CB<7>")
	)
	(segment
		(start 265.369548 -239.391698)
		(end 264.825226 -239.391698)
		(width 0.20066)
		(layer "F.Cu")
		(net "M_D_CPU0_SB_CB<7>")
	)
	(segment
		(start 262.003794 -239.09274)
		(end 261.87781 -238.966756)
		(width 0.20066)
		(layer "F.Cu")
		(net "M_D_CPU0_SB_CB<7>")
	)
	(segment
		(start 262.146288 -239.405922)
		(end 262.003794 -239.263428)
		(width 0.20066)
		(layer "F.Cu")
		(net "M_D_CPU0_SB_CB<7>")
	)
	(segment
		(start 262.50011 -239.405922)
		(end 262.146288 -239.405922)
		(width 0.20066)
		(layer "F.Cu")
		(net "M_D_CPU0_SB_CB<7>")
	)
	(segment
		(start 266.90828 -238.966756)
		(end 266.700762 -239.174274)
		(width 0.20066)
		(layer "F.Cu")
		(net "M_D_CPU0_SB_CB<7>")
	)
	(segment
		(start 266.042394 -238.962438)
		(end 265.64717 -238.962438)
		(width 0.20066)
		(layer "F.Cu")
		(net "M_D_CPU0_SB_CB<7>")
	)
	(segment
		(start 268.829282 -238.966756)
		(end 267.724382 -238.966756)
		(width 0.20066)
		(layer "F.Cu")
		(net "M_D_CPU0_SB_CB<7>")
	)
	(segment
		(start 265.64717 -238.962438)
		(end 265.518646 -239.090962)
		(width 0.20066)
		(layer "F.Cu")
		(net "M_D_CPU0_SB_CB<7>")
	)
	(segment
		(start 266.700762 -239.174274)
		(end 266.25423 -239.174274)
		(width 0.20066)
		(layer "F.Cu")
		(net "M_D_CPU0_SB_CB<7>")
	)
	(segment
		(start 264.825226 -239.391698)
		(end 262.752332 -239.391698)
		(width 0.1016)
		(layer "F.Cu")
		(net "M_D_CPU0_SB_CB<7>")
	)
	(segment
		(start 348.30258 -246.08663)
		(end 348.302834 -246.086376)
		(width 0.20066)
		(layer "F.Cu")
		(net "M_D_CPU0_SB_CB<7>")
	)
	(segment
		(start 265.518646 -239.090962)
		(end 265.518646 -239.2426)
		(width 0.20066)
		(layer "F.Cu")
		(net "M_D_CPU0_SB_CB<7>")
	)
	(segment
		(start 262.003794 -239.263428)
		(end 262.003794 -239.09274)
		(width 0.20066)
		(layer "F.Cu")
		(net "M_D_CPU0_SB_CB<7>")
	)
	(segment
		(start 261.87781 -238.966756)
		(end 260.180582 -238.966756)
		(width 0.20066)
		(layer "F.Cu")
		(net "M_D_CPU0_SB_CB<7>")
	)
	(segment
		(start 319.074546 -244.06733)
		(end 314.534042 -239.526826)
		(width 0.18288)
		(layer "In11.Cu")
		(net "M_D_CPU0_SB_CB<7>")
	)
	(segment
		(start 338.162646 -245.868952)
		(end 338.152232 -245.875048)
		(width 0.088646)
		(layer "In11.Cu")
		(net "M_D_CPU0_SB_CB<7>")
	)
	(segment
		(start 312.601356 -238.727488)
		(end 311.29478 -238.727488)
		(width 0.18288)
		(layer "In11.Cu")
		(net "M_D_CPU0_SB_CB<7>")
	)
	(segment
		(start 273.383248 -239.386872)
		(end 273.212814 -239.557306)
		(width 0.18288)
		(layer "In11.Cu")
		(net "M_D_CPU0_SB_CB<7>")
	)
	(segment
		(start 270.812006 -239.364266)
		(end 270.618966 -239.557306)
		(width 0.18288)
		(layer "In11.Cu")
		(net "M_D_CPU0_SB_CB<7>")
	)
	(segment
		(start 332.326234 -244.985286)
		(end 332.156054 -244.985286)
		(width 0.088646)
		(layer "In11.Cu")
		(net "M_D_CPU0_SB_CB<7>")
	)
	(segment
		(start 337.227164 -245.866412)
		(end 337.212432 -245.875048)
		(width 0.088646)
		(layer "In11.Cu")
		(net "M_D_CPU0_SB_CB<7>")
	)
	(segment
		(start 281.217116 -240.408206)
		(end 281.049984 -240.241074)
		(width 0.18288)
		(layer "In11.Cu")
		(net "M_D_CPU0_SB_CB<7>")
	)
	(segment
		(start 330.139548 -244.624352)
		(end 329.582526 -244.06733)
		(width 0.18288)
		(layer "In11.Cu")
		(net "M_D_CPU0_SB_CB<7>")
	)
	(segment
		(start 273.212814 -239.557306)
		(end 271.706086 -239.557306)
		(width 0.18288)
		(layer "In11.Cu")
		(net "M_D_CPU0_SB_CB<7>")
	)
	(segment
		(start 344.741246 -245.868952)
		(end 344.730832 -245.875048)
		(width 0.088646)
		(layer "In11.Cu")
		(net "M_D_CPU0_SB_CB<7>")
	)
	(segment
		(start 348.302834 -245.55069)
		(end 347.579442 -245.85803)
		(width 0.088646)
		(layer "In11.Cu")
		(net "M_D_CPU0_SB_CB<7>")
	)
	(segment
		(start 310.391556 -239.630712)
		(end 307.633116 -239.630712)
		(width 0.18288)
		(layer "In11.Cu")
		(net "M_D_CPU0_SB_CB<7>")
	)
	(segment
		(start 336.287364 -245.866412)
		(end 336.272632 -245.875048)
		(width 0.088646)
		(layer "In11.Cu")
		(net "M_D_CPU0_SB_CB<7>")
	)
	(segment
		(start 271.513046 -239.032288)
		(end 271.320006 -238.839248)
		(width 0.18288)
		(layer "In11.Cu")
		(net "M_D_CPU0_SB_CB<7>")
	)
	(segment
		(start 271.320006 -238.839248)
		(end 271.005046 -238.839248)
		(width 0.18288)
		(layer "In11.Cu")
		(net "M_D_CPU0_SB_CB<7>")
	)
	(segment
		(start 277.180294 -239.603026)
		(end 276.96414 -239.386872)
		(width 0.18288)
		(layer "In11.Cu")
		(net "M_D_CPU0_SB_CB<7>")
	)
	(segment
		(start 288.915094 -238.612426)
		(end 287.949894 -239.577626)
		(width 0.18288)
		(layer "In11.Cu")
		(net "M_D_CPU0_SB_CB<7>")
	)
	(segment
		(start 283.427678 -239.39119)
		(end 282.410662 -240.408206)
		(width 0.18288)
		(layer "In11.Cu")
		(net "M_D_CPU0_SB_CB<7>")
	)
	(segment
		(start 332.891384 -245.55069)
		(end 332.891384 -245.536466)
		(width 0.088646)
		(layer "In11.Cu")
		(net "M_D_CPU0_SB_CB<7>")
	)
	(segment
		(start 314.202064 -239.389412)
		(end 313.26328 -239.389412)
		(width 0.18288)
		(layer "In11.Cu")
		(net "M_D_CPU0_SB_CB<7>")
	)
	(segment
		(start 287.949894 -239.577626)
		(end 284.520894 -239.577626)
		(width 0.18288)
		(layer "In11.Cu")
		(net "M_D_CPU0_SB_CB<7>")
	)
	(segment
		(start 346.610432 -245.226332)
		(end 346.610178 -245.226332)
		(width 0.088646)
		(layer "In11.Cu")
		(net "M_D_CPU0_SB_CB<7>")
	)
	(segment
		(start 269.419832 -239.557306)
		(end 268.829282 -238.966756)
		(width 0.18288)
		(layer "In11.Cu")
		(net "M_D_CPU0_SB_CB<7>")
	)
	(segment
		(start 329.582526 -244.06733)
		(end 319.074546 -244.06733)
		(width 0.18288)
		(layer "In11.Cu")
		(net "M_D_CPU0_SB_CB<7>")
	)
	(segment
		(start 281.049984 -240.241074)
		(end 279.430988 -240.241074)
		(width 0.18288)
		(layer "In11.Cu")
		(net "M_D_CPU0_SB_CB<7>")
	)
	(segment
		(start 274.596606 -239.386872)
		(end 273.383248 -239.386872)
		(width 0.18288)
		(layer "In11.Cu")
		(net "M_D_CPU0_SB_CB<7>")
	)
	(segment
		(start 275.683726 -239.386872)
		(end 275.490686 -239.579912)
		(width 0.18288)
		(layer "In11.Cu")
		(net "M_D_CPU0_SB_CB<7>")
	)
	(segment
		(start 295.315894 -240.241074)
		(end 294.594788 -240.241074)
		(width 0.18288)
		(layer "In11.Cu")
		(net "M_D_CPU0_SB_CB<7>")
	)
	(segment
		(start 340.042246 -245.868952)
		(end 340.031832 -245.875048)
		(width 0.088646)
		(layer "In11.Cu")
		(net "M_D_CPU0_SB_CB<7>")
	)
	(segment
		(start 271.513046 -239.364266)
		(end 271.513046 -239.032288)
		(width 0.18288)
		(layer "In11.Cu")
		(net "M_D_CPU0_SB_CB<7>")
	)
	(segment
		(start 279.430988 -240.241074)
		(end 278.79294 -239.603026)
		(width 0.18288)
		(layer "In11.Cu")
		(net "M_D_CPU0_SB_CB<7>")
	)
	(segment
		(start 303.146968 -239.514634)
		(end 300.062138 -239.514634)
		(width 0.18288)
		(layer "In11.Cu")
		(net "M_D_CPU0_SB_CB<7>")
	)
	(segment
		(start 347.175836 -245.875048)
		(end 346.889832 -245.709694)
		(width 0.088646)
		(layer "In11.Cu")
		(net "M_D_CPU0_SB_CB<7>")
	)
	(segment
		(start 347.550232 -245.875048)
		(end 347.549978 -245.875048)
		(width 0.088646)
		(layer "In11.Cu")
		(net "M_D_CPU0_SB_CB<7>")
	)
	(segment
		(start 332.156054 -244.985286)
		(end 331.79512 -244.624352)
		(width 0.088646)
		(layer "In11.Cu")
		(net "M_D_CPU0_SB_CB<7>")
	)
	(segment
		(start 274.789646 -239.688116)
		(end 274.789646 -239.579912)
		(width 0.18288)
		(layer "In11.Cu")
		(net "M_D_CPU0_SB_CB<7>")
	)
	(segment
		(start 346.610432 -245.226586)
		(end 346.610432 -245.226332)
		(width 0.088646)
		(layer "In11.Cu")
		(net "M_D_CPU0_SB_CB<7>")
	)
	(segment
		(start 270.618966 -239.557306)
		(end 269.419832 -239.557306)
		(width 0.18288)
		(layer "In11.Cu")
		(net "M_D_CPU0_SB_CB<7>")
	)
	(segment
		(start 346.236036 -245.226332)
		(end 345.949778 -245.39194)
		(width 0.088646)
		(layer "In11.Cu")
		(net "M_D_CPU0_SB_CB<7>")
	)
	(segment
		(start 307.633116 -239.630712)
		(end 306.694078 -238.691674)
		(width 0.18288)
		(layer "In11.Cu")
		(net "M_D_CPU0_SB_CB<7>")
	)
	(segment
		(start 314.534042 -239.526826)
		(end 314.202064 -239.389412)
		(width 0.18288)
		(layer "In11.Cu")
		(net "M_D_CPU0_SB_CB<7>")
	)
	(segment
		(start 278.79294 -239.603026)
		(end 277.180294 -239.603026)
		(width 0.18288)
		(layer "In11.Cu")
		(net "M_D_CPU0_SB_CB<7>")
	)
	(segment
		(start 300.062138 -239.514634)
		(end 299.938694 -239.39119)
		(width 0.18288)
		(layer "In11.Cu")
		(net "M_D_CPU0_SB_CB<7>")
	)
	(segment
		(start 345.670632 -245.874794)
		(end 345.670378 -245.875048)
		(width 0.088646)
		(layer "In11.Cu")
		(net "M_D_CPU0_SB_CB<7>")
	)
	(segment
		(start 291.709094 -238.612426)
		(end 288.915094 -238.612426)
		(width 0.18288)
		(layer "In11.Cu")
		(net "M_D_CPU0_SB_CB<7>")
	)
	(segment
		(start 333.078836 -245.875048)
		(end 333.069946 -245.869968)
		(width 0.088646)
		(layer "In11.Cu")
		(net "M_D_CPU0_SB_CB<7>")
	)
	(segment
		(start 284.520894 -239.577626)
		(end 284.334458 -239.39119)
		(width 0.18288)
		(layer "In11.Cu")
		(net "M_D_CPU0_SB_CB<7>")
	)
	(segment
		(start 276.96414 -239.386872)
		(end 275.683726 -239.386872)
		(width 0.18288)
		(layer "In11.Cu")
		(net "M_D_CPU0_SB_CB<7>")
	)
	(segment
		(start 294.020748 -239.667034)
		(end 292.763702 -239.667034)
		(width 0.18288)
		(layer "In11.Cu")
		(net "M_D_CPU0_SB_CB<7>")
	)
	(segment
		(start 343.805764 -245.866412)
		(end 343.791032 -245.875048)
		(width 0.088646)
		(layer "In11.Cu")
		(net "M_D_CPU0_SB_CB<7>")
	)
	(segment
		(start 331.79512 -244.624352)
		(end 331.613764 -244.624352)
		(width 0.088646)
		(layer "In11.Cu")
		(net "M_D_CPU0_SB_CB<7>")
	)
	(segment
		(start 303.969928 -238.691674)
		(end 303.146968 -239.514634)
		(width 0.18288)
		(layer "In11.Cu")
		(net "M_D_CPU0_SB_CB<7>")
	)
	(segment
		(start 296.97426 -240.419128)
		(end 295.493948 -240.419128)
		(width 0.18288)
		(layer "In11.Cu")
		(net "M_D_CPU0_SB_CB<7>")
	)
	(segment
		(start 295.493948 -240.419128)
		(end 295.315894 -240.241074)
		(width 0.18288)
		(layer "In11.Cu")
		(net "M_D_CPU0_SB_CB<7>")
	)
	(segment
		(start 311.29478 -238.727488)
		(end 310.391556 -239.630712)
		(width 0.18288)
		(layer "In11.Cu")
		(net "M_D_CPU0_SB_CB<7>")
	)
	(segment
		(start 294.594788 -240.241074)
		(end 294.020748 -239.667034)
		(width 0.18288)
		(layer "In11.Cu")
		(net "M_D_CPU0_SB_CB<7>")
	)
	(segment
		(start 284.334458 -239.39119)
		(end 283.427678 -239.39119)
		(width 0.18288)
		(layer "In11.Cu")
		(net "M_D_CPU0_SB_CB<7>")
	)
	(segment
		(start 274.789646 -239.579912)
		(end 274.596606 -239.386872)
		(width 0.18288)
		(layer "In11.Cu")
		(net "M_D_CPU0_SB_CB<7>")
	)
	(segment
		(start 306.694078 -238.691674)
		(end 303.969928 -238.691674)
		(width 0.18288)
		(layer "In11.Cu")
		(net "M_D_CPU0_SB_CB<7>")
	)
	(segment
		(start 275.297646 -239.881156)
		(end 274.982686 -239.881156)
		(width 0.18288)
		(layer "In11.Cu")
		(net "M_D_CPU0_SB_CB<7>")
	)
	(segment
		(start 270.812006 -239.032288)
		(end 270.812006 -239.364266)
		(width 0.18288)
		(layer "In11.Cu")
		(net "M_D_CPU0_SB_CB<7>")
	)
	(segment
		(start 275.490686 -239.688116)
		(end 275.297646 -239.881156)
		(width 0.18288)
		(layer "In11.Cu")
		(net "M_D_CPU0_SB_CB<7>")
	)
	(segment
		(start 292.763702 -239.667034)
		(end 291.709094 -238.612426)
		(width 0.18288)
		(layer "In11.Cu")
		(net "M_D_CPU0_SB_CB<7>")
	)
	(segment
		(start 313.26328 -239.389412)
		(end 312.601356 -238.727488)
		(width 0.18288)
		(layer "In11.Cu")
		(net "M_D_CPU0_SB_CB<7>")
	)
	(segment
		(start 347.579442 -245.85803)
		(end 347.550232 -245.875048)
		(width 0.088646)
		(layer "In11.Cu")
		(net "M_D_CPU0_SB_CB<7>")
	)
	(segment
		(start 331.613764 -244.624352)
		(end 330.139548 -244.624352)
		(width 0.18288)
		(layer "In11.Cu")
		(net "M_D_CPU0_SB_CB<7>")
	)
	(segment
		(start 282.410662 -240.408206)
		(end 281.217116 -240.408206)
		(width 0.18288)
		(layer "In11.Cu")
		(net "M_D_CPU0_SB_CB<7>")
	)
	(segment
		(start 271.706086 -239.557306)
		(end 271.513046 -239.364266)
		(width 0.18288)
		(layer "In11.Cu")
		(net "M_D_CPU0_SB_CB<7>")
	)
	(segment
		(start 299.938694 -239.39119)
		(end 298.002198 -239.39119)
		(width 0.18288)
		(layer "In11.Cu")
		(net "M_D_CPU0_SB_CB<7>")
	)
	(segment
		(start 275.490686 -239.579912)
		(end 275.490686 -239.688116)
		(width 0.18288)
		(layer "In11.Cu")
		(net "M_D_CPU0_SB_CB<7>")
	)
	(segment
		(start 298.002198 -239.39119)
		(end 296.97426 -240.419128)
		(width 0.18288)
		(layer "In11.Cu")
		(net "M_D_CPU0_SB_CB<7>")
	)
	(segment
		(start 342.865964 -245.866412)
		(end 342.851232 -245.875048)
		(width 0.088646)
		(layer "In11.Cu")
		(net "M_D_CPU0_SB_CB<7>")
	)
	(segment
		(start 340.981792 -245.868952)
		(end 340.971378 -245.875048)
		(width 0.088646)
		(layer "In11.Cu")
		(net "M_D_CPU0_SB_CB<7>")
	)
	(segment
		(start 274.982686 -239.881156)
		(end 274.789646 -239.688116)
		(width 0.18288)
		(layer "In11.Cu")
		(net "M_D_CPU0_SB_CB<7>")
	)
	(segment
		(start 339.102192 -245.868952)
		(end 339.091778 -245.875048)
		(width 0.088646)
		(layer "In11.Cu")
		(net "M_D_CPU0_SB_CB<7>")
	)
	(segment
		(start 271.005046 -238.839248)
		(end 270.812006 -239.032288)
		(width 0.18288)
		(layer "In11.Cu")
		(net "M_D_CPU0_SB_CB<7>")
	)
	(arc
		(start 336.272632 -245.875048)
		(mid 336.085434 -245.925191)
		(end 335.898236 -245.875048)
		(width 0.088646)
		(layer "In11.Cu")
		(net "M_D_CPU0_SB_CB<7>")
	)
	(arc
		(start 346.610178 -245.226332)
		(mid 346.423124 -245.176282)
		(end 346.236036 -245.226332)
		(width 0.088646)
		(layer "In11.Cu")
		(net "M_D_CPU0_SB_CB<7>")
	)
	(arc
		(start 334.958436 -245.875048)
		(mid 334.675734 -245.799272)
		(end 334.393032 -245.875048)
		(width 0.088646)
		(layer "In11.Cu")
		(net "M_D_CPU0_SB_CB<7>")
	)
	(arc
		(start 345.949778 -245.39194)
		(mid 345.882512 -245.458988)
		(end 345.85783 -245.55069)
		(width 0.088646)
		(layer "In11.Cu")
		(net "M_D_CPU0_SB_CB<7>")
	)
	(arc
		(start 336.838036 -245.875048)
		(mid 336.563837 -245.799213)
		(end 336.287364 -245.866412)
		(width 0.088646)
		(layer "In11.Cu")
		(net "M_D_CPU0_SB_CB<7>")
	)
	(arc
		(start 346.797884 -245.55069)
		(mid 346.747591 -245.363514)
		(end 346.610432 -245.226586)
		(width 0.088646)
		(layer "In11.Cu")
		(net "M_D_CPU0_SB_CB<7>")
	)
	(arc
		(start 340.596982 -245.875048)
		(mid 340.320423 -245.799305)
		(end 340.042246 -245.868952)
		(width 0.088646)
		(layer "In11.Cu")
		(net "M_D_CPU0_SB_CB<7>")
	)
	(arc
		(start 345.295982 -245.875048)
		(mid 345.019423 -245.799305)
		(end 344.741246 -245.868952)
		(width 0.088646)
		(layer "In11.Cu")
		(net "M_D_CPU0_SB_CB<7>")
	)
	(arc
		(start 340.031832 -245.875048)
		(mid 339.844634 -245.925191)
		(end 339.657436 -245.875048)
		(width 0.088646)
		(layer "In11.Cu")
		(net "M_D_CPU0_SB_CB<7>")
	)
	(arc
		(start 345.670378 -245.875048)
		(mid 345.48318 -245.925225)
		(end 345.295982 -245.875048)
		(width 0.088646)
		(layer "In11.Cu")
		(net "M_D_CPU0_SB_CB<7>")
	)
	(arc
		(start 340.971378 -245.875048)
		(mid 340.78418 -245.925191)
		(end 340.596982 -245.875048)
		(width 0.088646)
		(layer "In11.Cu")
		(net "M_D_CPU0_SB_CB<7>")
	)
	(arc
		(start 333.069946 -245.869968)
		(mid 332.939032 -245.733608)
		(end 332.891384 -245.55069)
		(width 0.088646)
		(layer "In11.Cu")
		(net "M_D_CPU0_SB_CB<7>")
	)
	(arc
		(start 332.891384 -245.536466)
		(mid 332.812165 -245.261781)
		(end 332.608682 -245.060978)
		(width 0.088646)
		(layer "In11.Cu")
		(net "M_D_CPU0_SB_CB<7>")
	)
	(arc
		(start 335.332832 -245.875048)
		(mid 335.145634 -245.925191)
		(end 334.958436 -245.875048)
		(width 0.088646)
		(layer "In11.Cu")
		(net "M_D_CPU0_SB_CB<7>")
	)
	(arc
		(start 347.549978 -245.875048)
		(mid 347.362924 -245.925098)
		(end 347.175836 -245.875048)
		(width 0.088646)
		(layer "In11.Cu")
		(net "M_D_CPU0_SB_CB<7>")
	)
	(arc
		(start 341.911432 -245.875048)
		(mid 341.724234 -245.925191)
		(end 341.537036 -245.875048)
		(width 0.088646)
		(layer "In11.Cu")
		(net "M_D_CPU0_SB_CB<7>")
	)
	(arc
		(start 335.898236 -245.875048)
		(mid 335.615534 -245.799272)
		(end 335.332832 -245.875048)
		(width 0.088646)
		(layer "In11.Cu")
		(net "M_D_CPU0_SB_CB<7>")
	)
	(arc
		(start 339.657436 -245.875048)
		(mid 339.380623 -245.799178)
		(end 339.102192 -245.868952)
		(width 0.088646)
		(layer "In11.Cu")
		(net "M_D_CPU0_SB_CB<7>")
	)
	(arc
		(start 343.416636 -245.875048)
		(mid 343.142437 -245.799213)
		(end 342.865964 -245.866412)
		(width 0.088646)
		(layer "In11.Cu")
		(net "M_D_CPU0_SB_CB<7>")
	)
	(arc
		(start 341.537036 -245.875048)
		(mid 341.260223 -245.799178)
		(end 340.981792 -245.868952)
		(width 0.088646)
		(layer "In11.Cu")
		(net "M_D_CPU0_SB_CB<7>")
	)
	(arc
		(start 338.717382 -245.875048)
		(mid 338.440823 -245.799305)
		(end 338.162646 -245.868952)
		(width 0.088646)
		(layer "In11.Cu")
		(net "M_D_CPU0_SB_CB<7>")
	)
	(arc
		(start 333.453232 -245.875048)
		(mid 333.266034 -245.925191)
		(end 333.078836 -245.875048)
		(width 0.088646)
		(layer "In11.Cu")
		(net "M_D_CPU0_SB_CB<7>")
	)
	(arc
		(start 344.730832 -245.875048)
		(mid 344.543634 -245.925191)
		(end 344.356436 -245.875048)
		(width 0.088646)
		(layer "In11.Cu")
		(net "M_D_CPU0_SB_CB<7>")
	)
	(arc
		(start 332.608682 -245.060978)
		(mid 332.472439 -245.004532)
		(end 332.326234 -244.985286)
		(width 0.088646)
		(layer "In11.Cu")
		(net "M_D_CPU0_SB_CB<7>")
	)
	(arc
		(start 339.091778 -245.875048)
		(mid 338.90458 -245.925191)
		(end 338.717382 -245.875048)
		(width 0.088646)
		(layer "In11.Cu")
		(net "M_D_CPU0_SB_CB<7>")
	)
	(arc
		(start 334.393032 -245.875048)
		(mid 334.205834 -245.925191)
		(end 334.018636 -245.875048)
		(width 0.088646)
		(layer "In11.Cu")
		(net "M_D_CPU0_SB_CB<7>")
	)
	(arc
		(start 337.212432 -245.875048)
		(mid 337.025234 -245.925191)
		(end 336.838036 -245.875048)
		(width 0.088646)
		(layer "In11.Cu")
		(net "M_D_CPU0_SB_CB<7>")
	)
	(arc
		(start 343.791032 -245.875048)
		(mid 343.603834 -245.925191)
		(end 343.416636 -245.875048)
		(width 0.088646)
		(layer "In11.Cu")
		(net "M_D_CPU0_SB_CB<7>")
	)
	(arc
		(start 342.476836 -245.875048)
		(mid 342.194134 -245.799272)
		(end 341.911432 -245.875048)
		(width 0.088646)
		(layer "In11.Cu")
		(net "M_D_CPU0_SB_CB<7>")
	)
	(arc
		(start 342.851232 -245.875048)
		(mid 342.664034 -245.925191)
		(end 342.476836 -245.875048)
		(width 0.088646)
		(layer "In11.Cu")
		(net "M_D_CPU0_SB_CB<7>")
	)
	(arc
		(start 338.152232 -245.875048)
		(mid 337.965034 -245.925191)
		(end 337.777836 -245.875048)
		(width 0.088646)
		(layer "In11.Cu")
		(net "M_D_CPU0_SB_CB<7>")
	)
	(arc
		(start 346.889832 -245.709694)
		(mid 346.822502 -245.642536)
		(end 346.797884 -245.55069)
		(width 0.088646)
		(layer "In11.Cu")
		(net "M_D_CPU0_SB_CB<7>")
	)
	(arc
		(start 344.356436 -245.875048)
		(mid 344.082237 -245.799213)
		(end 343.805764 -245.866412)
		(width 0.088646)
		(layer "In11.Cu")
		(net "M_D_CPU0_SB_CB<7>")
	)
	(arc
		(start 334.018636 -245.875048)
		(mid 333.735934 -245.799272)
		(end 333.453232 -245.875048)
		(width 0.088646)
		(layer "In11.Cu")
		(net "M_D_CPU0_SB_CB<7>")
	)
	(arc
		(start 337.777836 -245.875048)
		(mid 337.503637 -245.799213)
		(end 337.227164 -245.866412)
		(width 0.088646)
		(layer "In11.Cu")
		(net "M_D_CPU0_SB_CB<7>")
	)
	(arc
		(start 345.85783 -245.55069)
		(mid 345.807666 -245.737828)
		(end 345.670632 -245.874794)
		(width 0.088646)
		(layer "In11.Cu")
		(net "M_D_CPU0_SB_CB<7>")
	)
	(segment
		(start 266.197842 -240.878614)
		(end 265.769344 -240.878614)
		(width 0.20066)
		(layer "F.Cu")
		(net "M_D_CPU0_SB_CB<6>")
	)
	(segment
		(start 264.825226 -240.241836)
		(end 262.765286 -240.241836)
		(width 0.1016)
		(layer "F.Cu")
		(net "M_D_CPU0_SB_CB<6>")
	)
	(segment
		(start 265.601958 -240.711228)
		(end 265.601958 -240.3856)
		(width 0.20066)
		(layer "F.Cu")
		(net "M_D_CPU0_SB_CB<6>")
	)
	(segment
		(start 265.601958 -240.3856)
		(end 265.458194 -240.241836)
		(width 0.20066)
		(layer "F.Cu")
		(net "M_D_CPU0_SB_CB<6>")
	)
	(segment
		(start 261.762748 -240.231676)
		(end 261.327646 -240.666778)
		(width 0.20066)
		(layer "F.Cu")
		(net "M_D_CPU0_SB_CB<6>")
	)
	(segment
		(start 347.832934 -246.900446)
		(end 347.83268 -246.900192)
		(width 0.20066)
		(layer "F.Cu")
		(net "M_D_CPU0_SB_CB<6>")
	)
	(segment
		(start 262.50011 -240.231676)
		(end 261.762748 -240.231676)
		(width 0.20066)
		(layer "F.Cu")
		(net "M_D_CPU0_SB_CB<6>")
	)
	(segment
		(start 266.409678 -240.666778)
		(end 266.197842 -240.878614)
		(width 0.20066)
		(layer "F.Cu")
		(net "M_D_CPU0_SB_CB<6>")
	)
	(segment
		(start 262.765286 -240.241836)
		(end 262.51027 -240.241836)
		(width 0.101854)
		(layer "F.Cu")
		(net "M_D_CPU0_SB_CB<6>")
	)
	(segment
		(start 268.829282 -240.666778)
		(end 267.724382 -240.666778)
		(width 0.20066)
		(layer "F.Cu")
		(net "M_D_CPU0_SB_CB<6>")
	)
	(segment
		(start 265.769344 -240.878614)
		(end 265.601958 -240.711228)
		(width 0.20066)
		(layer "F.Cu")
		(net "M_D_CPU0_SB_CB<6>")
	)
	(segment
		(start 262.51027 -240.241836)
		(end 262.50011 -240.231676)
		(width 0.101854)
		(layer "F.Cu")
		(net "M_D_CPU0_SB_CB<6>")
	)
	(segment
		(start 267.724382 -240.666778)
		(end 266.409678 -240.666778)
		(width 0.20066)
		(layer "F.Cu")
		(net "M_D_CPU0_SB_CB<6>")
	)
	(segment
		(start 265.458194 -240.241836)
		(end 264.825226 -240.241836)
		(width 0.20066)
		(layer "F.Cu")
		(net "M_D_CPU0_SB_CB<6>")
	)
	(segment
		(start 347.83268 -246.900192)
		(end 347.83268 -246.364506)
		(width 0.20066)
		(layer "F.Cu")
		(net "M_D_CPU0_SB_CB<6>")
	)
	(segment
		(start 261.327646 -240.666778)
		(end 260.180582 -240.666778)
		(width 0.20066)
		(layer "F.Cu")
		(net "M_D_CPU0_SB_CB<6>")
	)
	(segment
		(start 347.484446 -246.165878)
		(end 347.222826 -246.098568)
		(width 0.088646)
		(layer "In11.Cu")
		(net "M_D_CPU0_SB_CB<6>")
	)
	(segment
		(start 293.94531 -241.242342)
		(end 292.611556 -241.242342)
		(width 0.18288)
		(layer "In11.Cu")
		(net "M_D_CPU0_SB_CB<6>")
	)
	(segment
		(start 277.104094 -241.000026)
		(end 273.497294 -241.000026)
		(width 0.18288)
		(layer "In11.Cu")
		(net "M_D_CPU0_SB_CB<6>")
	)
	(segment
		(start 314.12942 -240.822226)
		(end 312.73369 -240.822226)
		(width 0.18288)
		(layer "In11.Cu")
		(net "M_D_CPU0_SB_CB<6>")
	)
	(segment
		(start 290.582096 -239.672876)
		(end 290.267136 -239.672876)
		(width 0.18288)
		(layer "In11.Cu")
		(net "M_D_CPU0_SB_CB<6>")
	)
	(segment
		(start 286.88411 -241.182906)
		(end 286.69107 -240.989866)
		(width 0.18288)
		(layer "In11.Cu")
		(net "M_D_CPU0_SB_CB<6>")
	)
	(segment
		(start 332.044802 -245.645178)
		(end 331.614018 -245.645178)
		(width 0.088646)
		(layer "In11.Cu")
		(net "M_D_CPU0_SB_CB<6>")
	)
	(segment
		(start 290.775136 -239.865916)
		(end 290.582096 -239.672876)
		(width 0.18288)
		(layer "In11.Cu")
		(net "M_D_CPU0_SB_CB<6>")
	)
	(segment
		(start 312.165746 -240.254282)
		(end 311.380886 -240.254282)
		(width 0.18288)
		(layer "In11.Cu")
		(net "M_D_CPU0_SB_CB<6>")
	)
	(segment
		(start 300.986444 -241.120676)
		(end 300.793404 -241.313716)
		(width 0.18288)
		(layer "In11.Cu")
		(net "M_D_CPU0_SB_CB<6>")
	)
	(segment
		(start 299.795438 -241.313716)
		(end 299.572934 -241.091212)
		(width 0.18288)
		(layer "In11.Cu")
		(net "M_D_CPU0_SB_CB<6>")
	)
	(segment
		(start 301.494444 -240.643664)
		(end 301.179484 -240.643664)
		(width 0.18288)
		(layer "In11.Cu")
		(net "M_D_CPU0_SB_CB<6>")
	)
	(segment
		(start 279.580086 -241.94135)
		(end 278.892762 -241.254026)
		(width 0.18288)
		(layer "In11.Cu")
		(net "M_D_CPU0_SB_CB<6>")
	)
	(segment
		(start 290.968176 -240.427256)
		(end 290.775136 -240.234216)
		(width 0.18288)
		(layer "In11.Cu")
		(net "M_D_CPU0_SB_CB<6>")
	)
	(segment
		(start 280.78811 -242.08105)
		(end 280.64841 -241.94135)
		(width 0.18288)
		(layer "In11.Cu")
		(net "M_D_CPU0_SB_CB<6>")
	)
	(segment
		(start 312.73369 -240.822226)
		(end 312.165746 -240.254282)
		(width 0.18288)
		(layer "In11.Cu")
		(net "M_D_CPU0_SB_CB<6>")
	)
	(segment
		(start 346.417646 -246.438674)
		(end 346.257118 -246.599202)
		(width 0.088646)
		(layer "In11.Cu")
		(net "M_D_CPU0_SB_CB<6>")
	)
	(segment
		(start 318.390524 -245.08333)
		(end 314.12942 -240.822226)
		(width 0.18288)
		(layer "In11.Cu")
		(net "M_D_CPU0_SB_CB<6>")
	)
	(segment
		(start 295.452546 -242.168172)
		(end 295.22547 -241.941096)
		(width 0.18288)
		(layer "In11.Cu")
		(net "M_D_CPU0_SB_CB<6>")
	)
	(segment
		(start 306.86121 -240.384584)
		(end 303.876456 -240.384584)
		(width 0.18288)
		(layer "In11.Cu")
		(net "M_D_CPU0_SB_CB<6>")
	)
	(segment
		(start 299.572934 -241.091212)
		(end 298.32808 -241.091212)
		(width 0.18288)
		(layer "In11.Cu")
		(net "M_D_CPU0_SB_CB<6>")
	)
	(segment
		(start 273.497294 -241.000026)
		(end 273.272504 -241.224816)
		(width 0.18288)
		(layer "In11.Cu")
		(net "M_D_CPU0_SB_CB<6>")
	)
	(segment
		(start 286.69107 -240.83772)
		(end 286.49803 -240.64468)
		(width 0.18288)
		(layer "In11.Cu")
		(net "M_D_CPU0_SB_CB<6>")
	)
	(segment
		(start 301.179484 -240.643664)
		(end 300.986444 -240.836704)
		(width 0.18288)
		(layer "In11.Cu")
		(net "M_D_CPU0_SB_CB<6>")
	)
	(segment
		(start 270.567404 -241.224816)
		(end 269.38732 -241.224816)
		(width 0.18288)
		(layer "In11.Cu")
		(net "M_D_CPU0_SB_CB<6>")
	)
	(segment
		(start 329.582272 -245.645178)
		(end 329.020424 -245.08333)
		(width 0.18288)
		(layer "In11.Cu")
		(net "M_D_CPU0_SB_CB<6>")
	)
	(segment
		(start 271.268444 -240.582958)
		(end 270.953484 -240.582958)
		(width 0.18288)
		(layer "In11.Cu")
		(net "M_D_CPU0_SB_CB<6>")
	)
	(segment
		(start 289.881056 -240.427256)
		(end 289.391344 -240.427256)
		(width 0.18288)
		(layer "In11.Cu")
		(net "M_D_CPU0_SB_CB<6>")
	)
	(segment
		(start 290.267136 -239.672876)
		(end 290.074096 -239.865916)
		(width 0.18288)
		(layer "In11.Cu")
		(net "M_D_CPU0_SB_CB<6>")
	)
	(segment
		(start 333.012796 -246.613172)
		(end 332.044802 -245.645178)
		(width 0.088646)
		(layer "In11.Cu")
		(net "M_D_CPU0_SB_CB<6>")
	)
	(segment
		(start 270.760444 -240.775998)
		(end 270.760444 -241.031776)
		(width 0.18288)
		(layer "In11.Cu")
		(net "M_D_CPU0_SB_CB<6>")
	)
	(segment
		(start 294.644064 -241.941096)
		(end 293.94531 -241.242342)
		(width 0.18288)
		(layer "In11.Cu")
		(net "M_D_CPU0_SB_CB<6>")
	)
	(segment
		(start 300.986444 -240.836704)
		(end 300.986444 -241.120676)
		(width 0.18288)
		(layer "In11.Cu")
		(net "M_D_CPU0_SB_CB<6>")
	)
	(segment
		(start 307.755036 -241.27841)
		(end 306.86121 -240.384584)
		(width 0.18288)
		(layer "In11.Cu")
		(net "M_D_CPU0_SB_CB<6>")
	)
	(segment
		(start 291.79647 -240.427256)
		(end 290.968176 -240.427256)
		(width 0.18288)
		(layer "In11.Cu")
		(net "M_D_CPU0_SB_CB<6>")
	)
	(segment
		(start 273.272504 -241.224816)
		(end 271.654524 -241.224816)
		(width 0.18288)
		(layer "In11.Cu")
		(net "M_D_CPU0_SB_CB<6>")
	)
	(segment
		(start 329.020424 -245.08333)
		(end 318.390524 -245.08333)
		(width 0.18288)
		(layer "In11.Cu")
		(net "M_D_CPU0_SB_CB<6>")
	)
	(segment
		(start 331.614018 -245.645178)
		(end 329.582272 -245.645178)
		(width 0.18288)
		(layer "In11.Cu")
		(net "M_D_CPU0_SB_CB<6>")
	)
	(segment
		(start 290.074096 -240.234216)
		(end 289.881056 -240.427256)
		(width 0.18288)
		(layer "In11.Cu")
		(net "M_D_CPU0_SB_CB<6>")
	)
	(segment
		(start 277.358094 -241.254026)
		(end 277.104094 -241.000026)
		(width 0.18288)
		(layer "In11.Cu")
		(net "M_D_CPU0_SB_CB<6>")
	)
	(segment
		(start 286.69107 -240.989866)
		(end 286.69107 -240.83772)
		(width 0.18288)
		(layer "In11.Cu")
		(net "M_D_CPU0_SB_CB<6>")
	)
	(segment
		(start 280.64841 -241.94135)
		(end 279.580086 -241.94135)
		(width 0.18288)
		(layer "In11.Cu")
		(net "M_D_CPU0_SB_CB<6>")
	)
	(segment
		(start 292.611556 -241.242342)
		(end 291.79647 -240.427256)
		(width 0.18288)
		(layer "In11.Cu")
		(net "M_D_CPU0_SB_CB<6>")
	)
	(segment
		(start 285.79699 -241.182906)
		(end 284.637988 -241.182906)
		(width 0.18288)
		(layer "In11.Cu")
		(net "M_D_CPU0_SB_CB<6>")
	)
	(segment
		(start 284.637988 -241.182906)
		(end 284.546294 -241.091212)
		(width 0.18288)
		(layer "In11.Cu")
		(net "M_D_CPU0_SB_CB<6>")
	)
	(segment
		(start 333.266034 -246.613172)
		(end 333.012796 -246.613172)
		(width 0.088646)
		(layer "In11.Cu")
		(net "M_D_CPU0_SB_CB<6>")
	)
	(segment
		(start 285.99003 -240.83772)
		(end 285.99003 -240.989866)
		(width 0.18288)
		(layer "In11.Cu")
		(net "M_D_CPU0_SB_CB<6>")
	)
	(segment
		(start 345.765882 -246.688864)
		(end 345.75115 -246.680228)
		(width 0.088646)
		(layer "In11.Cu")
		(net "M_D_CPU0_SB_CB<6>")
	)
	(segment
		(start 270.953484 -240.582958)
		(end 270.760444 -240.775998)
		(width 0.18288)
		(layer "In11.Cu")
		(net "M_D_CPU0_SB_CB<6>")
	)
	(segment
		(start 346.705682 -246.040148)
		(end 346.588588 -246.107204)
		(width 0.088646)
		(layer "In11.Cu")
		(net "M_D_CPU0_SB_CB<6>")
	)
	(segment
		(start 271.461484 -241.031776)
		(end 271.461484 -240.775998)
		(width 0.18288)
		(layer "In11.Cu")
		(net "M_D_CPU0_SB_CB<6>")
	)
	(segment
		(start 290.074096 -239.865916)
		(end 290.074096 -240.234216)
		(width 0.18288)
		(layer "In11.Cu")
		(net "M_D_CPU0_SB_CB<6>")
	)
	(segment
		(start 336.367882 -246.688864)
		(end 336.357468 -246.682768)
		(width 0.088646)
		(layer "In11.Cu")
		(net "M_D_CPU0_SB_CB<6>")
	)
	(segment
		(start 270.760444 -241.031776)
		(end 270.567404 -241.224816)
		(width 0.18288)
		(layer "In11.Cu")
		(net "M_D_CPU0_SB_CB<6>")
	)
	(segment
		(start 343.886282 -246.688864)
		(end 343.87155 -246.680228)
		(width 0.088646)
		(layer "In11.Cu")
		(net "M_D_CPU0_SB_CB<6>")
	)
	(segment
		(start 285.99003 -240.989866)
		(end 285.79699 -241.182906)
		(width 0.18288)
		(layer "In11.Cu")
		(net "M_D_CPU0_SB_CB<6>")
	)
	(segment
		(start 301.687484 -240.836704)
		(end 301.494444 -240.643664)
		(width 0.18288)
		(layer "In11.Cu")
		(net "M_D_CPU0_SB_CB<6>")
	)
	(segment
		(start 339.187282 -246.688864)
		(end 339.17255 -246.680228)
		(width 0.088646)
		(layer "In11.Cu")
		(net "M_D_CPU0_SB_CB<6>")
	)
	(segment
		(start 283.372052 -241.091212)
		(end 282.382214 -242.08105)
		(width 0.18288)
		(layer "In11.Cu")
		(net "M_D_CPU0_SB_CB<6>")
	)
	(segment
		(start 342.006936 -246.688864)
		(end 341.996522 -246.682768)
		(width 0.088646)
		(layer "In11.Cu")
		(net "M_D_CPU0_SB_CB<6>")
	)
	(segment
		(start 337.307682 -246.688864)
		(end 337.29295 -246.680228)
		(width 0.088646)
		(layer "In11.Cu")
		(net "M_D_CPU0_SB_CB<6>")
	)
	(segment
		(start 300.793404 -241.313716)
		(end 299.795438 -241.313716)
		(width 0.18288)
		(layer "In11.Cu")
		(net "M_D_CPU0_SB_CB<6>")
	)
	(segment
		(start 290.775136 -240.234216)
		(end 290.775136 -239.865916)
		(width 0.18288)
		(layer "In11.Cu")
		(net "M_D_CPU0_SB_CB<6>")
	)
	(segment
		(start 342.946482 -246.688864)
		(end 342.936068 -246.682768)
		(width 0.088646)
		(layer "In11.Cu")
		(net "M_D_CPU0_SB_CB<6>")
	)
	(segment
		(start 341.066882 -246.688864)
		(end 341.05215 -246.680228)
		(width 0.088646)
		(layer "In11.Cu")
		(net "M_D_CPU0_SB_CB<6>")
	)
	(segment
		(start 298.32808 -241.091212)
		(end 297.25112 -242.168172)
		(width 0.18288)
		(layer "In11.Cu")
		(net "M_D_CPU0_SB_CB<6>")
	)
	(segment
		(start 303.876456 -240.384584)
		(end 302.947324 -241.313716)
		(width 0.18288)
		(layer "In11.Cu")
		(net "M_D_CPU0_SB_CB<6>")
	)
	(segment
		(start 284.546294 -241.091212)
		(end 283.372052 -241.091212)
		(width 0.18288)
		(layer "In11.Cu")
		(net "M_D_CPU0_SB_CB<6>")
	)
	(segment
		(start 310.356758 -241.27841)
		(end 307.755036 -241.27841)
		(width 0.18288)
		(layer "In11.Cu")
		(net "M_D_CPU0_SB_CB<6>")
	)
	(segment
		(start 269.38732 -241.224816)
		(end 268.829282 -240.666778)
		(width 0.18288)
		(layer "In11.Cu")
		(net "M_D_CPU0_SB_CB<6>")
	)
	(segment
		(start 271.654524 -241.224816)
		(end 271.461484 -241.031776)
		(width 0.18288)
		(layer "In11.Cu")
		(net "M_D_CPU0_SB_CB<6>")
	)
	(segment
		(start 288.635694 -241.182906)
		(end 286.88411 -241.182906)
		(width 0.18288)
		(layer "In11.Cu")
		(net "M_D_CPU0_SB_CB<6>")
	)
	(segment
		(start 295.22547 -241.941096)
		(end 294.644064 -241.941096)
		(width 0.18288)
		(layer "In11.Cu")
		(net "M_D_CPU0_SB_CB<6>")
	)
	(segment
		(start 301.880524 -241.313716)
		(end 301.687484 -241.120676)
		(width 0.18288)
		(layer "In11.Cu")
		(net "M_D_CPU0_SB_CB<6>")
	)
	(segment
		(start 278.892762 -241.254026)
		(end 277.358094 -241.254026)
		(width 0.18288)
		(layer "In11.Cu")
		(net "M_D_CPU0_SB_CB<6>")
	)
	(segment
		(start 302.947324 -241.313716)
		(end 301.880524 -241.313716)
		(width 0.18288)
		(layer "In11.Cu")
		(net "M_D_CPU0_SB_CB<6>")
	)
	(segment
		(start 282.382214 -242.08105)
		(end 280.78811 -242.08105)
		(width 0.18288)
		(layer "In11.Cu")
		(net "M_D_CPU0_SB_CB<6>")
	)
	(segment
		(start 301.687484 -241.120676)
		(end 301.687484 -240.836704)
		(width 0.18288)
		(layer "In11.Cu")
		(net "M_D_CPU0_SB_CB<6>")
	)
	(segment
		(start 311.380886 -240.254282)
		(end 310.356758 -241.27841)
		(width 0.18288)
		(layer "In11.Cu")
		(net "M_D_CPU0_SB_CB<6>")
	)
	(segment
		(start 286.49803 -240.64468)
		(end 286.18307 -240.64468)
		(width 0.18288)
		(layer "In11.Cu")
		(net "M_D_CPU0_SB_CB<6>")
	)
	(segment
		(start 289.391344 -240.427256)
		(end 288.635694 -241.182906)
		(width 0.18288)
		(layer "In11.Cu")
		(net "M_D_CPU0_SB_CB<6>")
	)
	(segment
		(start 286.18307 -240.64468)
		(end 285.99003 -240.83772)
		(width 0.18288)
		(layer "In11.Cu")
		(net "M_D_CPU0_SB_CB<6>")
	)
	(segment
		(start 297.25112 -242.168172)
		(end 295.452546 -242.168172)
		(width 0.18288)
		(layer "In11.Cu")
		(net "M_D_CPU0_SB_CB<6>")
	)
	(segment
		(start 271.461484 -240.775998)
		(end 271.268444 -240.582958)
		(width 0.18288)
		(layer "In11.Cu")
		(net "M_D_CPU0_SB_CB<6>")
	)
	(arc
		(start 346.471494 -246.308626)
		(mid 346.457496 -246.379)
		(end 346.417646 -246.438674)
		(width 0.088646)
		(layer "In11.Cu")
		(net "M_D_CPU0_SB_CB<6>")
	)
	(arc
		(start 339.17255 -246.680228)
		(mid 338.896075 -246.612908)
		(end 338.621878 -246.688864)
		(width 0.088646)
		(layer "In11.Cu")
		(net "M_D_CPU0_SB_CB<6>")
	)
	(arc
		(start 337.682078 -246.688864)
		(mid 337.49488 -246.739007)
		(end 337.307682 -246.688864)
		(width 0.088646)
		(layer "In11.Cu")
		(net "M_D_CPU0_SB_CB<6>")
	)
	(arc
		(start 337.29295 -246.680228)
		(mid 337.016475 -246.612908)
		(end 336.742278 -246.688864)
		(width 0.088646)
		(layer "In11.Cu")
		(net "M_D_CPU0_SB_CB<6>")
	)
	(arc
		(start 340.501478 -246.688864)
		(mid 340.31428 -246.739007)
		(end 340.127082 -246.688864)
		(width 0.088646)
		(layer "In11.Cu")
		(net "M_D_CPU0_SB_CB<6>")
	)
	(arc
		(start 343.320878 -246.688864)
		(mid 343.13368 -246.739007)
		(end 342.946482 -246.688864)
		(width 0.088646)
		(layer "In11.Cu")
		(net "M_D_CPU0_SB_CB<6>")
	)
	(arc
		(start 341.05215 -246.680228)
		(mid 340.775675 -246.612908)
		(end 340.501478 -246.688864)
		(width 0.088646)
		(layer "In11.Cu")
		(net "M_D_CPU0_SB_CB<6>")
	)
	(arc
		(start 338.621878 -246.688864)
		(mid 338.43468 -246.739007)
		(end 338.247482 -246.688864)
		(width 0.088646)
		(layer "In11.Cu")
		(net "M_D_CPU0_SB_CB<6>")
	)
	(arc
		(start 338.247482 -246.688864)
		(mid 337.96478 -246.613088)
		(end 337.682078 -246.688864)
		(width 0.088646)
		(layer "In11.Cu")
		(net "M_D_CPU0_SB_CB<6>")
	)
	(arc
		(start 347.080078 -246.040148)
		(mid 346.89288 -245.990005)
		(end 346.705682 -246.040148)
		(width 0.088646)
		(layer "In11.Cu")
		(net "M_D_CPU0_SB_CB<6>")
	)
	(arc
		(start 336.357468 -246.682768)
		(mid 336.07929 -246.613045)
		(end 335.802732 -246.688864)
		(width 0.088646)
		(layer "In11.Cu")
		(net "M_D_CPU0_SB_CB<6>")
	)
	(arc
		(start 341.441278 -246.688864)
		(mid 341.25408 -246.739007)
		(end 341.066882 -246.688864)
		(width 0.088646)
		(layer "In11.Cu")
		(net "M_D_CPU0_SB_CB<6>")
	)
	(arc
		(start 345.75115 -246.680228)
		(mid 345.474675 -246.612908)
		(end 345.200478 -246.688864)
		(width 0.088646)
		(layer "In11.Cu")
		(net "M_D_CPU0_SB_CB<6>")
	)
	(arc
		(start 342.381332 -246.688864)
		(mid 342.194134 -246.739007)
		(end 342.006936 -246.688864)
		(width 0.088646)
		(layer "In11.Cu")
		(net "M_D_CPU0_SB_CB<6>")
	)
	(arc
		(start 343.87155 -246.680228)
		(mid 343.595075 -246.612908)
		(end 343.320878 -246.688864)
		(width 0.088646)
		(layer "In11.Cu")
		(net "M_D_CPU0_SB_CB<6>")
	)
	(arc
		(start 336.742278 -246.688864)
		(mid 336.55508 -246.739007)
		(end 336.367882 -246.688864)
		(width 0.088646)
		(layer "In11.Cu")
		(net "M_D_CPU0_SB_CB<6>")
	)
	(arc
		(start 335.802732 -246.688864)
		(mid 335.615534 -246.739007)
		(end 335.428336 -246.688864)
		(width 0.088646)
		(layer "In11.Cu")
		(net "M_D_CPU0_SB_CB<6>")
	)
	(arc
		(start 346.257118 -246.599202)
		(mid 346.201645 -246.647874)
		(end 346.140278 -246.688864)
		(width 0.088646)
		(layer "In11.Cu")
		(net "M_D_CPU0_SB_CB<6>")
	)
	(arc
		(start 346.588588 -246.107204)
		(mid 346.502929 -246.192159)
		(end 346.471494 -246.308626)
		(width 0.088646)
		(layer "In11.Cu")
		(net "M_D_CPU0_SB_CB<6>")
	)
	(arc
		(start 335.428336 -246.688864)
		(mid 335.145634 -246.613088)
		(end 334.862932 -246.688864)
		(width 0.088646)
		(layer "In11.Cu")
		(net "M_D_CPU0_SB_CB<6>")
	)
	(arc
		(start 339.561678 -246.688864)
		(mid 339.37448 -246.739007)
		(end 339.187282 -246.688864)
		(width 0.088646)
		(layer "In11.Cu")
		(net "M_D_CPU0_SB_CB<6>")
	)
	(arc
		(start 334.488536 -246.688864)
		(mid 334.205834 -246.613088)
		(end 333.923132 -246.688864)
		(width 0.088646)
		(layer "In11.Cu")
		(net "M_D_CPU0_SB_CB<6>")
	)
	(arc
		(start 344.826082 -246.688864)
		(mid 344.54338 -246.613088)
		(end 344.260678 -246.688864)
		(width 0.088646)
		(layer "In11.Cu")
		(net "M_D_CPU0_SB_CB<6>")
	)
	(arc
		(start 347.222826 -246.098568)
		(mid 347.149447 -246.074257)
		(end 347.080078 -246.040148)
		(width 0.088646)
		(layer "In11.Cu")
		(net "M_D_CPU0_SB_CB<6>")
	)
	(arc
		(start 345.200478 -246.688864)
		(mid 345.01328 -246.739007)
		(end 344.826082 -246.688864)
		(width 0.088646)
		(layer "In11.Cu")
		(net "M_D_CPU0_SB_CB<6>")
	)
	(arc
		(start 333.548736 -246.688864)
		(mid 333.412367 -246.632422)
		(end 333.266034 -246.613172)
		(width 0.088646)
		(layer "In11.Cu")
		(net "M_D_CPU0_SB_CB<6>")
	)
	(arc
		(start 341.996522 -246.682768)
		(mid 341.71809 -246.612922)
		(end 341.441278 -246.688864)
		(width 0.088646)
		(layer "In11.Cu")
		(net "M_D_CPU0_SB_CB<6>")
	)
	(arc
		(start 344.260678 -246.688864)
		(mid 344.07348 -246.739007)
		(end 343.886282 -246.688864)
		(width 0.088646)
		(layer "In11.Cu")
		(net "M_D_CPU0_SB_CB<6>")
	)
	(arc
		(start 333.923132 -246.688864)
		(mid 333.735934 -246.739007)
		(end 333.548736 -246.688864)
		(width 0.088646)
		(layer "In11.Cu")
		(net "M_D_CPU0_SB_CB<6>")
	)
	(arc
		(start 346.140278 -246.688864)
		(mid 345.95308 -246.739007)
		(end 345.765882 -246.688864)
		(width 0.088646)
		(layer "In11.Cu")
		(net "M_D_CPU0_SB_CB<6>")
	)
	(arc
		(start 347.83268 -246.364506)
		(mid 347.67189 -246.241827)
		(end 347.484446 -246.165878)
		(width 0.088646)
		(layer "In11.Cu")
		(net "M_D_CPU0_SB_CB<6>")
	)
	(arc
		(start 340.127082 -246.688864)
		(mid 339.84438 -246.613088)
		(end 339.561678 -246.688864)
		(width 0.088646)
		(layer "In11.Cu")
		(net "M_D_CPU0_SB_CB<6>")
	)
	(arc
		(start 342.936068 -246.682768)
		(mid 342.65789 -246.613045)
		(end 342.381332 -246.688864)
		(width 0.088646)
		(layer "In11.Cu")
		(net "M_D_CPU0_SB_CB<6>")
	)
	(arc
		(start 334.862932 -246.688864)
		(mid 334.675734 -246.739007)
		(end 334.488536 -246.688864)
		(width 0.088646)
		(layer "In11.Cu")
		(net "M_D_CPU0_SB_CB<6>")
	)
	(segment
		(start 257.414776 -239.81664)
		(end 256.080514 -239.81664)
		(width 0.20066)
		(layer "F.Cu")
		(net "M_D_CPU0_SB_CB<5>")
	)
	(segment
		(start 258.28498 -239.545368)
		(end 258.28498 -239.873536)
		(width 0.20066)
		(layer "F.Cu")
		(net "M_D_CPU0_SB_CB<5>")
	)
	(segment
		(start 264.729214 -239.81664)
		(end 263.624314 -239.81664)
		(width 0.20066)
		(layer "F.Cu")
		(net "M_D_CPU0_SB_CB<5>")
	)
	(segment
		(start 346.42298 -246.08663)
		(end 346.423234 -246.086376)
		(width 0.20066)
		(layer "F.Cu")
		(net "M_D_CPU0_SB_CB<5>")
	)
	(segment
		(start 261.984998 -239.81664)
		(end 261.560056 -239.391698)
		(width 0.20066)
		(layer "F.Cu")
		(net "M_D_CPU0_SB_CB<5>")
	)
	(segment
		(start 263.624314 -239.81664)
		(end 261.984998 -239.81664)
		(width 0.20066)
		(layer "F.Cu")
		(net "M_D_CPU0_SB_CB<5>")
	)
	(segment
		(start 257.626104 -240.027968)
		(end 257.414776 -239.81664)
		(width 0.20066)
		(layer "F.Cu")
		(net "M_D_CPU0_SB_CB<5>")
	)
	(segment
		(start 261.050786 -239.391698)
		(end 259.065268 -239.391698)
		(width 0.1016)
		(layer "F.Cu")
		(net "M_D_CPU0_SB_CB<5>")
	)
	(segment
		(start 261.381494 -239.391698)
		(end 261.050786 -239.391698)
		(width 0.101854)
		(layer "F.Cu")
		(net "M_D_CPU0_SB_CB<5>")
	)
	(segment
		(start 258.28498 -239.873536)
		(end 258.130548 -240.027968)
		(width 0.20066)
		(layer "F.Cu")
		(net "M_D_CPU0_SB_CB<5>")
	)
	(segment
		(start 258.130548 -240.027968)
		(end 257.626104 -240.027968)
		(width 0.20066)
		(layer "F.Cu")
		(net "M_D_CPU0_SB_CB<5>")
	)
	(segment
		(start 261.560056 -239.391698)
		(end 261.381494 -239.391698)
		(width 0.20066)
		(layer "F.Cu")
		(net "M_D_CPU0_SB_CB<5>")
	)
	(segment
		(start 258.44754 -239.382808)
		(end 258.28498 -239.545368)
		(width 0.20066)
		(layer "F.Cu")
		(net "M_D_CPU0_SB_CB<5>")
	)
	(segment
		(start 259.056378 -239.382808)
		(end 258.44754 -239.382808)
		(width 0.20066)
		(layer "F.Cu")
		(net "M_D_CPU0_SB_CB<5>")
	)
	(segment
		(start 259.065268 -239.391698)
		(end 259.056378 -239.382808)
		(width 0.1016)
		(layer "F.Cu")
		(net "M_D_CPU0_SB_CB<5>")
	)
	(segment
		(start 346.423234 -246.086376)
		(end 346.423234 -245.55069)
		(width 0.20066)
		(layer "F.Cu")
		(net "M_D_CPU0_SB_CB<5>")
	)
	(segment
		(start 273.128232 -240.072164)
		(end 269.550896 -240.072164)
		(width 0.18288)
		(layer "In11.Cu")
		(net "M_D_CPU0_SB_CB<5>")
	)
	(segment
		(start 318.680338 -244.57533)
		(end 314.38469 -240.279682)
		(width 0.18288)
		(layer "In11.Cu")
		(net "M_D_CPU0_SB_CB<5>")
	)
	(segment
		(start 277.152608 -240.163858)
		(end 276.904958 -240.411508)
		(width 0.18288)
		(layer "In11.Cu")
		(net "M_D_CPU0_SB_CB<5>")
	)
	(segment
		(start 332.029308 -245.175532)
		(end 331.986382 -245.132606)
		(width 0.088646)
		(layer "In11.Cu")
		(net "M_D_CPU0_SB_CB<5>")
	)
	(segment
		(start 273.467576 -240.411508)
		(end 273.128232 -240.072164)
		(width 0.18288)
		(layer "In11.Cu")
		(net "M_D_CPU0_SB_CB<5>")
	)
	(segment
		(start 289.223704 -239.145826)
		(end 288.254694 -240.114836)
		(width 0.18288)
		(layer "In11.Cu")
		(net "M_D_CPU0_SB_CB<5>")
	)
	(segment
		(start 297.202352 -240.996216)
		(end 295.358058 -240.996216)
		(width 0.18288)
		(layer "In11.Cu")
		(net "M_D_CPU0_SB_CB<5>")
	)
	(segment
		(start 295.263062 -241.091212)
		(end 294.68318 -241.091212)
		(width 0.18288)
		(layer "In11.Cu")
		(net "M_D_CPU0_SB_CB<5>")
	)
	(segment
		(start 342.946482 -246.040148)
		(end 342.936068 -246.046244)
		(width 0.088646)
		(layer "In11.Cu")
		(net "M_D_CPU0_SB_CB<5>")
	)
	(segment
		(start 340.127082 -246.040148)
		(end 340.11235 -246.048784)
		(width 0.088646)
		(layer "In11.Cu")
		(net "M_D_CPU0_SB_CB<5>")
	)
	(segment
		(start 306.54498 -239.26546)
		(end 304.172112 -239.26546)
		(width 0.18288)
		(layer "In11.Cu")
		(net "M_D_CPU0_SB_CB<5>")
	)
	(segment
		(start 284.263846 -240.241074)
		(end 283.398214 -240.241074)
		(width 0.18288)
		(layer "In11.Cu")
		(net "M_D_CPU0_SB_CB<5>")
	)
	(segment
		(start 332.32598 -245.175532)
		(end 332.029308 -245.175532)
		(width 0.088646)
		(layer "In11.Cu")
		(net "M_D_CPU0_SB_CB<5>")
	)
	(segment
		(start 337.307682 -246.040148)
		(end 337.29295 -246.048784)
		(width 0.088646)
		(layer "In11.Cu")
		(net "M_D_CPU0_SB_CB<5>")
	)
	(segment
		(start 343.886282 -246.040148)
		(end 343.87155 -246.048784)
		(width 0.088646)
		(layer "In11.Cu")
		(net "M_D_CPU0_SB_CB<5>")
	)
	(segment
		(start 280.667206 -240.98885)
		(end 280.564844 -241.091212)
		(width 0.18288)
		(layer "In11.Cu")
		(net "M_D_CPU0_SB_CB<5>")
	)
	(segment
		(start 311.521094 -239.349026)
		(end 310.670702 -240.199418)
		(width 0.18288)
		(layer "In11.Cu")
		(net "M_D_CPU0_SB_CB<5>")
	)
	(segment
		(start 312.171334 -239.349026)
		(end 311.521094 -239.349026)
		(width 0.18288)
		(layer "In11.Cu")
		(net "M_D_CPU0_SB_CB<5>")
	)
	(segment
		(start 288.254694 -240.114836)
		(end 284.390084 -240.114836)
		(width 0.18288)
		(layer "In11.Cu")
		(net "M_D_CPU0_SB_CB<5>")
	)
	(segment
		(start 280.564844 -241.091212)
		(end 279.468834 -241.091212)
		(width 0.18288)
		(layer "In11.Cu")
		(net "M_D_CPU0_SB_CB<5>")
	)
	(segment
		(start 332.700884 -245.560596)
		(end 332.700884 -245.55069)
		(width 0.088646)
		(layer "In11.Cu")
		(net "M_D_CPU0_SB_CB<5>")
	)
	(segment
		(start 294.68318 -241.091212)
		(end 293.804594 -240.212626)
		(width 0.18288)
		(layer "In11.Cu")
		(net "M_D_CPU0_SB_CB<5>")
	)
	(segment
		(start 269.550896 -240.072164)
		(end 269.381986 -240.241074)
		(width 0.18288)
		(layer "In11.Cu")
		(net "M_D_CPU0_SB_CB<5>")
	)
	(segment
		(start 291.506148 -239.145826)
		(end 289.223704 -239.145826)
		(width 0.18288)
		(layer "In11.Cu")
		(net "M_D_CPU0_SB_CB<5>")
	)
	(segment
		(start 293.804594 -240.212626)
		(end 292.572948 -240.212626)
		(width 0.18288)
		(layer "In11.Cu")
		(net "M_D_CPU0_SB_CB<5>")
	)
	(segment
		(start 292.572948 -240.212626)
		(end 291.506148 -239.145826)
		(width 0.18288)
		(layer "In11.Cu")
		(net "M_D_CPU0_SB_CB<5>")
	)
	(segment
		(start 268.247622 -240.241074)
		(end 267.226034 -239.219486)
		(width 0.18288)
		(layer "In11.Cu")
		(net "M_D_CPU0_SB_CB<5>")
	)
	(segment
		(start 338.247482 -246.040148)
		(end 338.23275 -246.048784)
		(width 0.088646)
		(layer "In11.Cu")
		(net "M_D_CPU0_SB_CB<5>")
	)
	(segment
		(start 299.938694 -240.241074)
		(end 297.957494 -240.241074)
		(width 0.18288)
		(layer "In11.Cu")
		(net "M_D_CPU0_SB_CB<5>")
	)
	(segment
		(start 282.650438 -240.98885)
		(end 280.667206 -240.98885)
		(width 0.18288)
		(layer "In11.Cu")
		(net "M_D_CPU0_SB_CB<5>")
	)
	(segment
		(start 278.54148 -240.163858)
		(end 277.152608 -240.163858)
		(width 0.18288)
		(layer "In11.Cu")
		(net "M_D_CPU0_SB_CB<5>")
	)
	(segment
		(start 345.84513 -245.994428)
		(end 345.765882 -246.040148)
		(width 0.088646)
		(layer "In11.Cu")
		(net "M_D_CPU0_SB_CB<5>")
	)
	(segment
		(start 329.929236 -245.132606)
		(end 329.37196 -244.57533)
		(width 0.18288)
		(layer "In11.Cu")
		(net "M_D_CPU0_SB_CB<5>")
	)
	(segment
		(start 283.398214 -240.241074)
		(end 282.650438 -240.98885)
		(width 0.18288)
		(layer "In11.Cu")
		(net "M_D_CPU0_SB_CB<5>")
	)
	(segment
		(start 303.351946 -240.085626)
		(end 300.094142 -240.085626)
		(width 0.18288)
		(layer "In11.Cu")
		(net "M_D_CPU0_SB_CB<5>")
	)
	(segment
		(start 297.957494 -240.241074)
		(end 297.202352 -240.996216)
		(width 0.18288)
		(layer "In11.Cu")
		(net "M_D_CPU0_SB_CB<5>")
	)
	(segment
		(start 310.670702 -240.199418)
		(end 307.478938 -240.199418)
		(width 0.18288)
		(layer "In11.Cu")
		(net "M_D_CPU0_SB_CB<5>")
	)
	(segment
		(start 284.390084 -240.114836)
		(end 284.263846 -240.241074)
		(width 0.18288)
		(layer "In11.Cu")
		(net "M_D_CPU0_SB_CB<5>")
	)
	(segment
		(start 295.358058 -240.996216)
		(end 295.263062 -241.091212)
		(width 0.18288)
		(layer "In11.Cu")
		(net "M_D_CPU0_SB_CB<5>")
	)
	(segment
		(start 313.10199 -240.279682)
		(end 312.171334 -239.349026)
		(width 0.18288)
		(layer "In11.Cu")
		(net "M_D_CPU0_SB_CB<5>")
	)
	(segment
		(start 300.094142 -240.085626)
		(end 299.938694 -240.241074)
		(width 0.18288)
		(layer "In11.Cu")
		(net "M_D_CPU0_SB_CB<5>")
	)
	(segment
		(start 279.468834 -241.091212)
		(end 278.54148 -240.163858)
		(width 0.18288)
		(layer "In11.Cu")
		(net "M_D_CPU0_SB_CB<5>")
	)
	(segment
		(start 307.478938 -240.199418)
		(end 306.54498 -239.26546)
		(width 0.18288)
		(layer "In11.Cu")
		(net "M_D_CPU0_SB_CB<5>")
	)
	(segment
		(start 344.826082 -246.040148)
		(end 344.81135 -246.048784)
		(width 0.088646)
		(layer "In11.Cu")
		(net "M_D_CPU0_SB_CB<5>")
	)
	(segment
		(start 304.172112 -239.26546)
		(end 303.351946 -240.085626)
		(width 0.18288)
		(layer "In11.Cu")
		(net "M_D_CPU0_SB_CB<5>")
	)
	(segment
		(start 342.006936 -246.040148)
		(end 341.996522 -246.046244)
		(width 0.088646)
		(layer "In11.Cu")
		(net "M_D_CPU0_SB_CB<5>")
	)
	(segment
		(start 331.614018 -245.132606)
		(end 329.929236 -245.132606)
		(width 0.18288)
		(layer "In11.Cu")
		(net "M_D_CPU0_SB_CB<5>")
	)
	(segment
		(start 336.367882 -246.040148)
		(end 336.357468 -246.046244)
		(width 0.088646)
		(layer "In11.Cu")
		(net "M_D_CPU0_SB_CB<5>")
	)
	(segment
		(start 331.986382 -245.132606)
		(end 331.614018 -245.132606)
		(width 0.088646)
		(layer "In11.Cu")
		(net "M_D_CPU0_SB_CB<5>")
	)
	(segment
		(start 267.226034 -239.219486)
		(end 265.326368 -239.219486)
		(width 0.18288)
		(layer "In11.Cu")
		(net "M_D_CPU0_SB_CB<5>")
	)
	(segment
		(start 269.381986 -240.241074)
		(end 268.247622 -240.241074)
		(width 0.18288)
		(layer "In11.Cu")
		(net "M_D_CPU0_SB_CB<5>")
	)
	(segment
		(start 329.37196 -244.57533)
		(end 318.680338 -244.57533)
		(width 0.18288)
		(layer "In11.Cu")
		(net "M_D_CPU0_SB_CB<5>")
	)
	(segment
		(start 276.904958 -240.411508)
		(end 273.467576 -240.411508)
		(width 0.18288)
		(layer "In11.Cu")
		(net "M_D_CPU0_SB_CB<5>")
	)
	(segment
		(start 314.38469 -240.279682)
		(end 313.10199 -240.279682)
		(width 0.18288)
		(layer "In11.Cu")
		(net "M_D_CPU0_SB_CB<5>")
	)
	(segment
		(start 265.326368 -239.219486)
		(end 264.729214 -239.81664)
		(width 0.18288)
		(layer "In11.Cu")
		(net "M_D_CPU0_SB_CB<5>")
	)
	(segment
		(start 332.522322 -245.231412)
		(end 332.513432 -245.226332)
		(width 0.088646)
		(layer "In11.Cu")
		(net "M_D_CPU0_SB_CB<5>")
	)
	(arc
		(start 337.29295 -246.048784)
		(mid 337.016475 -246.116104)
		(end 336.742278 -246.040148)
		(width 0.088646)
		(layer "In11.Cu")
		(net "M_D_CPU0_SB_CB<5>")
	)
	(arc
		(start 345.200478 -246.040148)
		(mid 345.01328 -245.990005)
		(end 344.826082 -246.040148)
		(width 0.088646)
		(layer "In11.Cu")
		(net "M_D_CPU0_SB_CB<5>")
	)
	(arc
		(start 336.742278 -246.040148)
		(mid 336.55508 -245.990005)
		(end 336.367882 -246.040148)
		(width 0.088646)
		(layer "In11.Cu")
		(net "M_D_CPU0_SB_CB<5>")
	)
	(arc
		(start 340.501478 -246.040148)
		(mid 340.31428 -245.990005)
		(end 340.127082 -246.040148)
		(width 0.088646)
		(layer "In11.Cu")
		(net "M_D_CPU0_SB_CB<5>")
	)
	(arc
		(start 332.700884 -245.55069)
		(mid 332.653205 -245.36779)
		(end 332.522322 -245.231412)
		(width 0.088646)
		(layer "In11.Cu")
		(net "M_D_CPU0_SB_CB<5>")
	)
	(arc
		(start 342.381332 -246.040148)
		(mid 342.194134 -245.990005)
		(end 342.006936 -246.040148)
		(width 0.088646)
		(layer "In11.Cu")
		(net "M_D_CPU0_SB_CB<5>")
	)
	(arc
		(start 341.996522 -246.046244)
		(mid 341.71809 -246.11609)
		(end 341.441278 -246.040148)
		(width 0.088646)
		(layer "In11.Cu")
		(net "M_D_CPU0_SB_CB<5>")
	)
	(arc
		(start 344.81135 -246.048784)
		(mid 344.534875 -246.116104)
		(end 344.260678 -246.040148)
		(width 0.088646)
		(layer "In11.Cu")
		(net "M_D_CPU0_SB_CB<5>")
	)
	(arc
		(start 335.428336 -246.040148)
		(mid 335.145634 -246.115924)
		(end 334.862932 -246.040148)
		(width 0.088646)
		(layer "In11.Cu")
		(net "M_D_CPU0_SB_CB<5>")
	)
	(arc
		(start 343.87155 -246.048784)
		(mid 343.595075 -246.116104)
		(end 343.320878 -246.040148)
		(width 0.088646)
		(layer "In11.Cu")
		(net "M_D_CPU0_SB_CB<5>")
	)
	(arc
		(start 334.862932 -246.040148)
		(mid 334.675734 -245.990005)
		(end 334.488536 -246.040148)
		(width 0.088646)
		(layer "In11.Cu")
		(net "M_D_CPU0_SB_CB<5>")
	)
	(arc
		(start 343.320878 -246.040148)
		(mid 343.13368 -245.990005)
		(end 342.946482 -246.040148)
		(width 0.088646)
		(layer "In11.Cu")
		(net "M_D_CPU0_SB_CB<5>")
	)
	(arc
		(start 344.260678 -246.040148)
		(mid 344.07348 -245.990005)
		(end 343.886282 -246.040148)
		(width 0.088646)
		(layer "In11.Cu")
		(net "M_D_CPU0_SB_CB<5>")
	)
	(arc
		(start 332.983332 -246.040148)
		(mid 332.778997 -245.837543)
		(end 332.700884 -245.560596)
		(width 0.088646)
		(layer "In11.Cu")
		(net "M_D_CPU0_SB_CB<5>")
	)
	(arc
		(start 339.561678 -246.040148)
		(mid 339.37448 -245.990005)
		(end 339.187282 -246.040148)
		(width 0.088646)
		(layer "In11.Cu")
		(net "M_D_CPU0_SB_CB<5>")
	)
	(arc
		(start 340.11235 -246.048784)
		(mid 339.835875 -246.116104)
		(end 339.561678 -246.040148)
		(width 0.088646)
		(layer "In11.Cu")
		(net "M_D_CPU0_SB_CB<5>")
	)
	(arc
		(start 345.765882 -246.040148)
		(mid 345.48318 -246.115924)
		(end 345.200478 -246.040148)
		(width 0.088646)
		(layer "In11.Cu")
		(net "M_D_CPU0_SB_CB<5>")
	)
	(arc
		(start 341.066882 -246.040148)
		(mid 340.78418 -246.115924)
		(end 340.501478 -246.040148)
		(width 0.088646)
		(layer "In11.Cu")
		(net "M_D_CPU0_SB_CB<5>")
	)
	(arc
		(start 342.936068 -246.046244)
		(mid 342.65789 -246.115967)
		(end 342.381332 -246.040148)
		(width 0.088646)
		(layer "In11.Cu")
		(net "M_D_CPU0_SB_CB<5>")
	)
	(arc
		(start 333.923132 -246.040148)
		(mid 333.735934 -245.990005)
		(end 333.548736 -246.040148)
		(width 0.088646)
		(layer "In11.Cu")
		(net "M_D_CPU0_SB_CB<5>")
	)
	(arc
		(start 339.187282 -246.040148)
		(mid 338.90458 -246.115924)
		(end 338.621878 -246.040148)
		(width 0.088646)
		(layer "In11.Cu")
		(net "M_D_CPU0_SB_CB<5>")
	)
	(arc
		(start 338.621878 -246.040148)
		(mid 338.43468 -245.990005)
		(end 338.247482 -246.040148)
		(width 0.088646)
		(layer "In11.Cu")
		(net "M_D_CPU0_SB_CB<5>")
	)
	(arc
		(start 334.488536 -246.040148)
		(mid 334.205834 -246.115924)
		(end 333.923132 -246.040148)
		(width 0.088646)
		(layer "In11.Cu")
		(net "M_D_CPU0_SB_CB<5>")
	)
	(arc
		(start 336.357468 -246.046244)
		(mid 336.07929 -246.115967)
		(end 335.802732 -246.040148)
		(width 0.088646)
		(layer "In11.Cu")
		(net "M_D_CPU0_SB_CB<5>")
	)
	(arc
		(start 337.682078 -246.040148)
		(mid 337.49488 -245.990005)
		(end 337.307682 -246.040148)
		(width 0.088646)
		(layer "In11.Cu")
		(net "M_D_CPU0_SB_CB<5>")
	)
	(arc
		(start 338.23275 -246.048784)
		(mid 337.956275 -246.116104)
		(end 337.682078 -246.040148)
		(width 0.088646)
		(layer "In11.Cu")
		(net "M_D_CPU0_SB_CB<5>")
	)
	(arc
		(start 341.441278 -246.040148)
		(mid 341.25408 -245.990005)
		(end 341.066882 -246.040148)
		(width 0.088646)
		(layer "In11.Cu")
		(net "M_D_CPU0_SB_CB<5>")
	)
	(arc
		(start 346.423234 -245.55069)
		(mid 346.148714 -245.791492)
		(end 345.84513 -245.994428)
		(width 0.088646)
		(layer "In11.Cu")
		(net "M_D_CPU0_SB_CB<5>")
	)
	(arc
		(start 333.548736 -246.040148)
		(mid 333.266034 -246.115924)
		(end 332.983332 -246.040148)
		(width 0.088646)
		(layer "In11.Cu")
		(net "M_D_CPU0_SB_CB<5>")
	)
	(arc
		(start 332.513432 -245.226332)
		(mid 332.423053 -245.188577)
		(end 332.32598 -245.175532)
		(width 0.088646)
		(layer "In11.Cu")
		(net "M_D_CPU0_SB_CB<5>")
	)
	(arc
		(start 335.802732 -246.040148)
		(mid 335.615534 -245.990005)
		(end 335.428336 -246.040148)
		(width 0.088646)
		(layer "In11.Cu")
		(net "M_D_CPU0_SB_CB<5>")
	)
	(segment
		(start 258.28498 -241.293142)
		(end 258.28498 -241.582702)
		(width 0.20066)
		(layer "F.Cu")
		(net "M_D_CPU0_SB_CB<4>")
	)
	(segment
		(start 346.893134 -246.900446)
		(end 346.89288 -246.900192)
		(width 0.20066)
		(layer "F.Cu")
		(net "M_D_CPU0_SB_CB<4>")
	)
	(segment
		(start 264.729214 -241.516662)
		(end 263.624314 -241.516662)
		(width 0.20066)
		(layer "F.Cu")
		(net "M_D_CPU0_SB_CB<4>")
	)
	(segment
		(start 263.624314 -241.516662)
		(end 262.255254 -241.516662)
		(width 0.20066)
		(layer "F.Cu")
		(net "M_D_CPU0_SB_CB<4>")
	)
	(segment
		(start 261.381494 -241.09172)
		(end 259.31241 -241.09172)
		(width 0.1016)
		(layer "F.Cu")
		(net "M_D_CPU0_SB_CB<4>")
	)
	(segment
		(start 257.414776 -241.516662)
		(end 256.080514 -241.516662)
		(width 0.20066)
		(layer "F.Cu")
		(net "M_D_CPU0_SB_CB<4>")
	)
	(segment
		(start 259.056378 -241.083592)
		(end 258.49453 -241.083592)
		(width 0.20066)
		(layer "F.Cu")
		(net "M_D_CPU0_SB_CB<4>")
	)
	(segment
		(start 258.49453 -241.083592)
		(end 258.28498 -241.293142)
		(width 0.20066)
		(layer "F.Cu")
		(net "M_D_CPU0_SB_CB<4>")
	)
	(segment
		(start 259.31241 -241.09172)
		(end 259.064506 -241.09172)
		(width 0.101854)
		(layer "F.Cu")
		(net "M_D_CPU0_SB_CB<4>")
	)
	(segment
		(start 257.653536 -241.755422)
		(end 257.414776 -241.516662)
		(width 0.20066)
		(layer "F.Cu")
		(net "M_D_CPU0_SB_CB<4>")
	)
	(segment
		(start 262.255254 -241.516662)
		(end 261.830312 -241.09172)
		(width 0.20066)
		(layer "F.Cu")
		(net "M_D_CPU0_SB_CB<4>")
	)
	(segment
		(start 258.11226 -241.755422)
		(end 257.653536 -241.755422)
		(width 0.20066)
		(layer "F.Cu")
		(net "M_D_CPU0_SB_CB<4>")
	)
	(segment
		(start 346.89288 -246.900192)
		(end 346.89288 -246.364506)
		(width 0.20066)
		(layer "F.Cu")
		(net "M_D_CPU0_SB_CB<4>")
	)
	(segment
		(start 258.28498 -241.582702)
		(end 258.11226 -241.755422)
		(width 0.20066)
		(layer "F.Cu")
		(net "M_D_CPU0_SB_CB<4>")
	)
	(segment
		(start 259.064506 -241.09172)
		(end 259.056378 -241.083592)
		(width 0.101854)
		(layer "F.Cu")
		(net "M_D_CPU0_SB_CB<4>")
	)
	(segment
		(start 261.830312 -241.09172)
		(end 261.381494 -241.09172)
		(width 0.20066)
		(layer "F.Cu")
		(net "M_D_CPU0_SB_CB<4>")
	)
	(segment
		(start 269.344394 -241.941096)
		(end 267.717524 -241.941096)
		(width 0.18288)
		(layer "In11.Cu")
		(net "M_D_CPU0_SB_CB<4>")
	)
	(segment
		(start 333.266034 -246.803418)
		(end 332.933802 -246.803418)
		(width 0.088646)
		(layer "In11.Cu")
		(net "M_D_CPU0_SB_CB<4>")
	)
	(segment
		(start 271.363948 -242.612672)
		(end 271.048988 -242.612672)
		(width 0.18288)
		(layer "In11.Cu")
		(net "M_D_CPU0_SB_CB<4>")
	)
	(segment
		(start 332.285594 -246.15521)
		(end 331.614018 -246.15521)
		(width 0.088646)
		(layer "In11.Cu")
		(net "M_D_CPU0_SB_CB<4>")
	)
	(segment
		(start 271.750028 -241.772186)
		(end 271.556988 -241.965226)
		(width 0.18288)
		(layer "In11.Cu")
		(net "M_D_CPU0_SB_CB<4>")
	)
	(segment
		(start 273.598894 -242.117626)
		(end 273.253454 -241.772186)
		(width 0.18288)
		(layer "In11.Cu")
		(net "M_D_CPU0_SB_CB<4>")
	)
	(segment
		(start 313.304936 -242.217956)
		(end 312.087006 -241.000026)
		(width 0.18288)
		(layer "In11.Cu")
		(net "M_D_CPU0_SB_CB<4>")
	)
	(segment
		(start 344.740992 -246.86006)
		(end 344.730578 -246.853964)
		(width 0.088646)
		(layer "In11.Cu")
		(net "M_D_CPU0_SB_CB<4>")
	)
	(segment
		(start 292.090094 -241.941096)
		(end 290.590224 -241.941096)
		(width 0.18288)
		(layer "In11.Cu")
		(net "M_D_CPU0_SB_CB<4>")
	)
	(segment
		(start 283.529024 -241.941096)
		(end 282.824936 -242.645184)
		(width 0.18288)
		(layer "In11.Cu")
		(net "M_D_CPU0_SB_CB<4>")
	)
	(segment
		(start 313.906916 -242.217956)
		(end 313.304936 -242.217956)
		(width 0.18288)
		(layer "In11.Cu")
		(net "M_D_CPU0_SB_CB<4>")
	)
	(segment
		(start 297.753786 -242.791234)
		(end 294.706802 -242.791234)
		(width 0.18288)
		(layer "In11.Cu")
		(net "M_D_CPU0_SB_CB<4>")
	)
	(segment
		(start 290.590224 -241.941096)
		(end 290.388294 -242.143026)
		(width 0.18288)
		(layer "In11.Cu")
		(net "M_D_CPU0_SB_CB<4>")
	)
	(segment
		(start 271.556988 -241.965226)
		(end 271.556988 -242.419632)
		(width 0.18288)
		(layer "In11.Cu")
		(net "M_D_CPU0_SB_CB<4>")
	)
	(segment
		(start 293.829994 -241.914426)
		(end 292.116764 -241.914426)
		(width 0.18288)
		(layer "In11.Cu")
		(net "M_D_CPU0_SB_CB<4>")
	)
	(segment
		(start 329.373484 -246.15521)
		(end 328.809604 -245.59133)
		(width 0.18288)
		(layer "In11.Cu")
		(net "M_D_CPU0_SB_CB<4>")
	)
	(segment
		(start 292.116764 -241.914426)
		(end 292.090094 -241.941096)
		(width 0.18288)
		(layer "In11.Cu")
		(net "M_D_CPU0_SB_CB<4>")
	)
	(segment
		(start 312.087006 -241.000026)
		(end 311.555638 -241.000026)
		(width 0.18288)
		(layer "In11.Cu")
		(net "M_D_CPU0_SB_CB<4>")
	)
	(segment
		(start 269.513304 -241.772186)
		(end 269.344394 -241.941096)
		(width 0.18288)
		(layer "In11.Cu")
		(net "M_D_CPU0_SB_CB<4>")
	)
	(segment
		(start 340.041992 -246.86006)
		(end 340.031578 -246.853964)
		(width 0.088646)
		(layer "In11.Cu")
		(net "M_D_CPU0_SB_CB<4>")
	)
	(segment
		(start 332.933802 -246.803418)
		(end 332.285594 -246.15521)
		(width 0.088646)
		(layer "In11.Cu")
		(net "M_D_CPU0_SB_CB<4>")
	)
	(segment
		(start 271.556988 -242.419632)
		(end 271.363948 -242.612672)
		(width 0.18288)
		(layer "In11.Cu")
		(net "M_D_CPU0_SB_CB<4>")
	)
	(segment
		(start 310.753506 -241.802158)
		(end 307.485034 -241.802158)
		(width 0.18288)
		(layer "In11.Cu")
		(net "M_D_CPU0_SB_CB<4>")
	)
	(segment
		(start 267.490194 -242.168426)
		(end 265.380978 -242.168426)
		(width 0.18288)
		(layer "In11.Cu")
		(net "M_D_CPU0_SB_CB<4>")
	)
	(segment
		(start 339.102446 -246.86006)
		(end 339.092032 -246.853964)
		(width 0.088646)
		(layer "In11.Cu")
		(net "M_D_CPU0_SB_CB<4>")
	)
	(segment
		(start 282.824936 -242.645184)
		(end 280.693368 -242.645184)
		(width 0.18288)
		(layer "In11.Cu")
		(net "M_D_CPU0_SB_CB<4>")
	)
	(segment
		(start 275.072094 -242.117626)
		(end 273.598894 -242.117626)
		(width 0.18288)
		(layer "In11.Cu")
		(net "M_D_CPU0_SB_CB<4>")
	)
	(segment
		(start 288.610294 -242.143026)
		(end 288.203894 -241.736626)
		(width 0.18288)
		(layer "In11.Cu")
		(net "M_D_CPU0_SB_CB<4>")
	)
	(segment
		(start 331.614018 -246.15521)
		(end 329.373484 -246.15521)
		(width 0.18288)
		(layer "In11.Cu")
		(net "M_D_CPU0_SB_CB<4>")
	)
	(segment
		(start 288.203894 -241.736626)
		(end 284.750764 -241.736626)
		(width 0.18288)
		(layer "In11.Cu")
		(net "M_D_CPU0_SB_CB<4>")
	)
	(segment
		(start 343.801446 -246.86006)
		(end 343.791032 -246.853964)
		(width 0.088646)
		(layer "In11.Cu")
		(net "M_D_CPU0_SB_CB<4>")
	)
	(segment
		(start 270.855948 -242.419632)
		(end 270.855948 -241.965226)
		(width 0.18288)
		(layer "In11.Cu")
		(net "M_D_CPU0_SB_CB<4>")
	)
	(segment
		(start 279.594056 -242.791488)
		(end 278.615394 -241.812826)
		(width 0.18288)
		(layer "In11.Cu")
		(net "M_D_CPU0_SB_CB<4>")
	)
	(segment
		(start 270.662908 -241.772186)
		(end 269.513304 -241.772186)
		(width 0.18288)
		(layer "In11.Cu")
		(net "M_D_CPU0_SB_CB<4>")
	)
	(segment
		(start 338.162392 -246.86006)
		(end 338.151978 -246.853964)
		(width 0.088646)
		(layer "In11.Cu")
		(net "M_D_CPU0_SB_CB<4>")
	)
	(segment
		(start 307.485034 -241.802158)
		(end 306.690776 -241.0079)
		(width 0.18288)
		(layer "In11.Cu")
		(net "M_D_CPU0_SB_CB<4>")
	)
	(segment
		(start 311.555638 -241.000026)
		(end 310.753506 -241.802158)
		(width 0.18288)
		(layer "In11.Cu")
		(net "M_D_CPU0_SB_CB<4>")
	)
	(segment
		(start 328.809604 -245.59133)
		(end 317.28029 -245.59133)
		(width 0.18288)
		(layer "In11.Cu")
		(net "M_D_CPU0_SB_CB<4>")
	)
	(segment
		(start 345.681046 -246.86006)
		(end 345.670632 -246.853964)
		(width 0.088646)
		(layer "In11.Cu")
		(net "M_D_CPU0_SB_CB<4>")
	)
	(segment
		(start 299.835824 -241.941096)
		(end 298.603924 -241.941096)
		(width 0.18288)
		(layer "In11.Cu")
		(net "M_D_CPU0_SB_CB<4>")
	)
	(segment
		(start 267.717524 -241.941096)
		(end 267.490194 -242.168426)
		(width 0.18288)
		(layer "In11.Cu")
		(net "M_D_CPU0_SB_CB<4>")
	)
	(segment
		(start 306.690776 -241.0079)
		(end 304.0761 -241.0079)
		(width 0.18288)
		(layer "In11.Cu")
		(net "M_D_CPU0_SB_CB<4>")
	)
	(segment
		(start 265.380978 -242.168426)
		(end 264.729214 -241.516662)
		(width 0.18288)
		(layer "In11.Cu")
		(net "M_D_CPU0_SB_CB<4>")
	)
	(segment
		(start 340.986364 -246.8626)
		(end 340.971632 -246.853964)
		(width 0.088646)
		(layer "In11.Cu")
		(net "M_D_CPU0_SB_CB<4>")
	)
	(segment
		(start 303.224946 -241.859054)
		(end 299.917866 -241.859054)
		(width 0.18288)
		(layer "In11.Cu")
		(net "M_D_CPU0_SB_CB<4>")
	)
	(segment
		(start 304.0761 -241.0079)
		(end 303.224946 -241.859054)
		(width 0.18288)
		(layer "In11.Cu")
		(net "M_D_CPU0_SB_CB<4>")
	)
	(segment
		(start 280.547064 -242.791488)
		(end 279.594056 -242.791488)
		(width 0.18288)
		(layer "In11.Cu")
		(net "M_D_CPU0_SB_CB<4>")
	)
	(segment
		(start 342.865964 -246.8626)
		(end 342.851232 -246.853964)
		(width 0.088646)
		(layer "In11.Cu")
		(net "M_D_CPU0_SB_CB<4>")
	)
	(segment
		(start 284.546294 -241.941096)
		(end 283.529024 -241.941096)
		(width 0.18288)
		(layer "In11.Cu")
		(net "M_D_CPU0_SB_CB<4>")
	)
	(segment
		(start 270.855948 -241.965226)
		(end 270.662908 -241.772186)
		(width 0.18288)
		(layer "In11.Cu")
		(net "M_D_CPU0_SB_CB<4>")
	)
	(segment
		(start 299.917866 -241.859054)
		(end 299.835824 -241.941096)
		(width 0.18288)
		(layer "In11.Cu")
		(net "M_D_CPU0_SB_CB<4>")
	)
	(segment
		(start 290.388294 -242.143026)
		(end 288.610294 -242.143026)
		(width 0.18288)
		(layer "In11.Cu")
		(net "M_D_CPU0_SB_CB<4>")
	)
	(segment
		(start 317.28029 -245.59133)
		(end 313.906916 -242.217956)
		(width 0.18288)
		(layer "In11.Cu")
		(net "M_D_CPU0_SB_CB<4>")
	)
	(segment
		(start 284.750764 -241.736626)
		(end 284.546294 -241.941096)
		(width 0.18288)
		(layer "In11.Cu")
		(net "M_D_CPU0_SB_CB<4>")
	)
	(segment
		(start 271.048988 -242.612672)
		(end 270.855948 -242.419632)
		(width 0.18288)
		(layer "In11.Cu")
		(net "M_D_CPU0_SB_CB<4>")
	)
	(segment
		(start 273.253454 -241.772186)
		(end 271.750028 -241.772186)
		(width 0.18288)
		(layer "In11.Cu")
		(net "M_D_CPU0_SB_CB<4>")
	)
	(segment
		(start 277.15337 -241.94135)
		(end 275.24837 -241.94135)
		(width 0.18288)
		(layer "In11.Cu")
		(net "M_D_CPU0_SB_CB<4>")
	)
	(segment
		(start 280.693368 -242.645184)
		(end 280.547064 -242.791488)
		(width 0.18288)
		(layer "In11.Cu")
		(net "M_D_CPU0_SB_CB<4>")
	)
	(segment
		(start 298.603924 -241.941096)
		(end 297.753786 -242.791234)
		(width 0.18288)
		(layer "In11.Cu")
		(net "M_D_CPU0_SB_CB<4>")
	)
	(segment
		(start 277.281894 -241.812826)
		(end 277.15337 -241.94135)
		(width 0.18288)
		(layer "In11.Cu")
		(net "M_D_CPU0_SB_CB<4>")
	)
	(segment
		(start 294.706802 -242.791234)
		(end 293.829994 -241.914426)
		(width 0.18288)
		(layer "In11.Cu")
		(net "M_D_CPU0_SB_CB<4>")
	)
	(segment
		(start 336.287364 -246.8626)
		(end 336.272632 -246.853964)
		(width 0.088646)
		(layer "In11.Cu")
		(net "M_D_CPU0_SB_CB<4>")
	)
	(segment
		(start 346.314014 -246.808752)
		(end 346.235782 -246.853964)
		(width 0.088646)
		(layer "In11.Cu")
		(net "M_D_CPU0_SB_CB<4>")
	)
	(segment
		(start 275.24837 -241.94135)
		(end 275.072094 -242.117626)
		(width 0.18288)
		(layer "In11.Cu")
		(net "M_D_CPU0_SB_CB<4>")
	)
	(segment
		(start 278.615394 -241.812826)
		(end 277.281894 -241.812826)
		(width 0.18288)
		(layer "In11.Cu")
		(net "M_D_CPU0_SB_CB<4>")
	)
	(segment
		(start 337.222846 -246.86006)
		(end 337.212432 -246.853964)
		(width 0.088646)
		(layer "In11.Cu")
		(net "M_D_CPU0_SB_CB<4>")
	)
	(arc
		(start 345.670632 -246.853964)
		(mid 345.483434 -246.803821)
		(end 345.296236 -246.853964)
		(width 0.088646)
		(layer "In11.Cu")
		(net "M_D_CPU0_SB_CB<4>")
	)
	(arc
		(start 336.272632 -246.853964)
		(mid 336.085434 -246.803821)
		(end 335.898236 -246.853964)
		(width 0.088646)
		(layer "In11.Cu")
		(net "M_D_CPU0_SB_CB<4>")
	)
	(arc
		(start 337.212432 -246.853964)
		(mid 337.025234 -246.803821)
		(end 336.838036 -246.853964)
		(width 0.088646)
		(layer "In11.Cu")
		(net "M_D_CPU0_SB_CB<4>")
	)
	(arc
		(start 343.791032 -246.853964)
		(mid 343.603834 -246.803821)
		(end 343.416636 -246.853964)
		(width 0.088646)
		(layer "In11.Cu")
		(net "M_D_CPU0_SB_CB<4>")
	)
	(arc
		(start 340.031578 -246.853964)
		(mid 339.84438 -246.803821)
		(end 339.657182 -246.853964)
		(width 0.088646)
		(layer "In11.Cu")
		(net "M_D_CPU0_SB_CB<4>")
	)
	(arc
		(start 334.393032 -246.853964)
		(mid 334.205834 -246.803821)
		(end 334.018636 -246.853964)
		(width 0.088646)
		(layer "In11.Cu")
		(net "M_D_CPU0_SB_CB<4>")
	)
	(arc
		(start 334.958436 -246.853964)
		(mid 334.675734 -246.92974)
		(end 334.393032 -246.853964)
		(width 0.088646)
		(layer "In11.Cu")
		(net "M_D_CPU0_SB_CB<4>")
	)
	(arc
		(start 341.911432 -246.853964)
		(mid 341.724234 -246.803821)
		(end 341.537036 -246.853964)
		(width 0.088646)
		(layer "In11.Cu")
		(net "M_D_CPU0_SB_CB<4>")
	)
	(arc
		(start 339.092032 -246.853964)
		(mid 338.904834 -246.803821)
		(end 338.717636 -246.853964)
		(width 0.088646)
		(layer "In11.Cu")
		(net "M_D_CPU0_SB_CB<4>")
	)
	(arc
		(start 339.657182 -246.853964)
		(mid 339.380623 -246.929707)
		(end 339.102446 -246.86006)
		(width 0.088646)
		(layer "In11.Cu")
		(net "M_D_CPU0_SB_CB<4>")
	)
	(arc
		(start 346.89288 -246.364506)
		(mid 346.617987 -246.605574)
		(end 346.314014 -246.808752)
		(width 0.088646)
		(layer "In11.Cu")
		(net "M_D_CPU0_SB_CB<4>")
	)
	(arc
		(start 345.296236 -246.853964)
		(mid 345.019423 -246.929834)
		(end 344.740992 -246.86006)
		(width 0.088646)
		(layer "In11.Cu")
		(net "M_D_CPU0_SB_CB<4>")
	)
	(arc
		(start 336.838036 -246.853964)
		(mid 336.563837 -246.929799)
		(end 336.287364 -246.8626)
		(width 0.088646)
		(layer "In11.Cu")
		(net "M_D_CPU0_SB_CB<4>")
	)
	(arc
		(start 335.898236 -246.853964)
		(mid 335.615534 -246.92974)
		(end 335.332832 -246.853964)
		(width 0.088646)
		(layer "In11.Cu")
		(net "M_D_CPU0_SB_CB<4>")
	)
	(arc
		(start 346.235782 -246.853964)
		(mid 345.959223 -246.929707)
		(end 345.681046 -246.86006)
		(width 0.088646)
		(layer "In11.Cu")
		(net "M_D_CPU0_SB_CB<4>")
	)
	(arc
		(start 334.018636 -246.853964)
		(mid 333.735934 -246.92974)
		(end 333.453232 -246.853964)
		(width 0.088646)
		(layer "In11.Cu")
		(net "M_D_CPU0_SB_CB<4>")
	)
	(arc
		(start 344.356182 -246.853964)
		(mid 344.079623 -246.929707)
		(end 343.801446 -246.86006)
		(width 0.088646)
		(layer "In11.Cu")
		(net "M_D_CPU0_SB_CB<4>")
	)
	(arc
		(start 340.971632 -246.853964)
		(mid 340.784434 -246.803821)
		(end 340.597236 -246.853964)
		(width 0.088646)
		(layer "In11.Cu")
		(net "M_D_CPU0_SB_CB<4>")
	)
	(arc
		(start 342.476836 -246.853964)
		(mid 342.194134 -246.92974)
		(end 341.911432 -246.853964)
		(width 0.088646)
		(layer "In11.Cu")
		(net "M_D_CPU0_SB_CB<4>")
	)
	(arc
		(start 338.717636 -246.853964)
		(mid 338.440823 -246.929834)
		(end 338.162392 -246.86006)
		(width 0.088646)
		(layer "In11.Cu")
		(net "M_D_CPU0_SB_CB<4>")
	)
	(arc
		(start 337.777582 -246.853964)
		(mid 337.501023 -246.929707)
		(end 337.222846 -246.86006)
		(width 0.088646)
		(layer "In11.Cu")
		(net "M_D_CPU0_SB_CB<4>")
	)
	(arc
		(start 341.537036 -246.853964)
		(mid 341.262837 -246.929799)
		(end 340.986364 -246.8626)
		(width 0.088646)
		(layer "In11.Cu")
		(net "M_D_CPU0_SB_CB<4>")
	)
	(arc
		(start 344.730578 -246.853964)
		(mid 344.54338 -246.803821)
		(end 344.356182 -246.853964)
		(width 0.088646)
		(layer "In11.Cu")
		(net "M_D_CPU0_SB_CB<4>")
	)
	(arc
		(start 335.332832 -246.853964)
		(mid 335.145634 -246.803821)
		(end 334.958436 -246.853964)
		(width 0.088646)
		(layer "In11.Cu")
		(net "M_D_CPU0_SB_CB<4>")
	)
	(arc
		(start 340.597236 -246.853964)
		(mid 340.320423 -246.929834)
		(end 340.041992 -246.86006)
		(width 0.088646)
		(layer "In11.Cu")
		(net "M_D_CPU0_SB_CB<4>")
	)
	(arc
		(start 338.151978 -246.853964)
		(mid 337.96478 -246.803821)
		(end 337.777582 -246.853964)
		(width 0.088646)
		(layer "In11.Cu")
		(net "M_D_CPU0_SB_CB<4>")
	)
	(arc
		(start 343.416636 -246.853964)
		(mid 343.142437 -246.929799)
		(end 342.865964 -246.8626)
		(width 0.088646)
		(layer "In11.Cu")
		(net "M_D_CPU0_SB_CB<4>")
	)
	(arc
		(start 342.851232 -246.853964)
		(mid 342.664034 -246.803821)
		(end 342.476836 -246.853964)
		(width 0.088646)
		(layer "In11.Cu")
		(net "M_D_CPU0_SB_CB<4>")
	)
	(arc
		(start 333.453232 -246.853964)
		(mid 333.36296 -246.816365)
		(end 333.266034 -246.803418)
		(width 0.088646)
		(layer "In11.Cu")
		(net "M_D_CPU0_SB_CB<4>")
	)
	(segment
		(start 262.752332 -233.441748)
		(end 262.514334 -233.441748)
		(width 0.101854)
		(layer "F.Cu")
		(net "M_D_CPU0_SB_CB<3>")
	)
	(segment
		(start 261.87781 -233.016806)
		(end 260.180582 -233.016806)
		(width 0.20066)
		(layer "F.Cu")
		(net "M_D_CPU0_SB_CB<3>")
	)
	(segment
		(start 262.003794 -233.14279)
		(end 261.87781 -233.016806)
		(width 0.20066)
		(layer "F.Cu")
		(net "M_D_CPU0_SB_CB<3>")
	)
	(segment
		(start 262.50011 -233.455972)
		(end 262.146288 -233.455972)
		(width 0.20066)
		(layer "F.Cu")
		(net "M_D_CPU0_SB_CB<3>")
	)
	(segment
		(start 266.700762 -233.224324)
		(end 266.25423 -233.224324)
		(width 0.20066)
		(layer "F.Cu")
		(net "M_D_CPU0_SB_CB<3>")
	)
	(segment
		(start 265.518646 -233.29265)
		(end 265.369548 -233.441748)
		(width 0.20066)
		(layer "F.Cu")
		(net "M_D_CPU0_SB_CB<3>")
	)
	(segment
		(start 264.825226 -233.441748)
		(end 262.752332 -233.441748)
		(width 0.1016)
		(layer "F.Cu")
		(net "M_D_CPU0_SB_CB<3>")
	)
	(segment
		(start 268.829282 -233.016806)
		(end 267.724382 -233.016806)
		(width 0.20066)
		(layer "F.Cu")
		(net "M_D_CPU0_SB_CB<3>")
	)
	(segment
		(start 262.514334 -233.441748)
		(end 262.50011 -233.455972)
		(width 0.101854)
		(layer "F.Cu")
		(net "M_D_CPU0_SB_CB<3>")
	)
	(segment
		(start 266.042394 -233.012488)
		(end 265.64717 -233.012488)
		(width 0.20066)
		(layer "F.Cu")
		(net "M_D_CPU0_SB_CB<3>")
	)
	(segment
		(start 347.832934 -243.644928)
		(end 347.83268 -243.644674)
		(width 0.20066)
		(layer "F.Cu")
		(net "M_D_CPU0_SB_CB<3>")
	)
	(segment
		(start 266.25423 -233.224324)
		(end 266.042394 -233.012488)
		(width 0.20066)
		(layer "F.Cu")
		(net "M_D_CPU0_SB_CB<3>")
	)
	(segment
		(start 262.146288 -233.455972)
		(end 262.003794 -233.313478)
		(width 0.20066)
		(layer "F.Cu")
		(net "M_D_CPU0_SB_CB<3>")
	)
	(segment
		(start 265.518646 -233.141012)
		(end 265.518646 -233.29265)
		(width 0.20066)
		(layer "F.Cu")
		(net "M_D_CPU0_SB_CB<3>")
	)
	(segment
		(start 266.90828 -233.016806)
		(end 266.700762 -233.224324)
		(width 0.20066)
		(layer "F.Cu")
		(net "M_D_CPU0_SB_CB<3>")
	)
	(segment
		(start 265.369548 -233.441748)
		(end 264.825226 -233.441748)
		(width 0.20066)
		(layer "F.Cu")
		(net "M_D_CPU0_SB_CB<3>")
	)
	(segment
		(start 265.64717 -233.012488)
		(end 265.518646 -233.141012)
		(width 0.20066)
		(layer "F.Cu")
		(net "M_D_CPU0_SB_CB<3>")
	)
	(segment
		(start 267.724382 -233.016806)
		(end 266.90828 -233.016806)
		(width 0.20066)
		(layer "F.Cu")
		(net "M_D_CPU0_SB_CB<3>")
	)
	(segment
		(start 347.83268 -243.644674)
		(end 347.83268 -243.108988)
		(width 0.20066)
		(layer "F.Cu")
		(net "M_D_CPU0_SB_CB<3>")
	)
	(segment
		(start 262.003794 -233.313478)
		(end 262.003794 -233.14279)
		(width 0.20066)
		(layer "F.Cu")
		(net "M_D_CPU0_SB_CB<3>")
	)
	(segment
		(start 315.860684 -234.960922)
		(end 314.754514 -234.502706)
		(width 0.18288)
		(layer "In11.Cu")
		(net "M_D_CPU0_SB_CB<3>")
	)
	(segment
		(start 291.810694 -232.618026)
		(end 291.175694 -232.618026)
		(width 0.18288)
		(layer "In11.Cu")
		(net "M_D_CPU0_SB_CB<3>")
	)
	(segment
		(start 340.986364 -242.61064)
		(end 340.971632 -242.619276)
		(width 0.088646)
		(layer "In11.Cu")
		(net "M_D_CPU0_SB_CB<3>")
	)
	(segment
		(start 305.551332 -232.134664)
		(end 305.236372 -232.134664)
		(width 0.18288)
		(layer "In11.Cu")
		(net "M_D_CPU0_SB_CB<3>")
	)
	(segment
		(start 332.998064 -241.796824)
		(end 332.983332 -241.80546)
		(width 0.088646)
		(layer "In11.Cu")
		(net "M_D_CPU0_SB_CB<3>")
	)
	(segment
		(start 346.625164 -242.61064)
		(end 346.610432 -242.619276)
		(width 0.088646)
		(layer "In11.Cu")
		(net "M_D_CPU0_SB_CB<3>")
	)
	(segment
		(start 277.931626 -233.629454)
		(end 277.277322 -233.629454)
		(width 0.18288)
		(layer "In11.Cu")
		(net "M_D_CPU0_SB_CB<3>")
	)
	(segment
		(start 297.652694 -231.424226)
		(end 296.584624 -231.424226)
		(width 0.18288)
		(layer "In11.Cu")
		(net "M_D_CPU0_SB_CB<3>")
	)
	(segment
		(start 340.046564 -242.61064)
		(end 340.031832 -242.619276)
		(width 0.088646)
		(layer "In11.Cu")
		(net "M_D_CPU0_SB_CB<3>")
	)
	(segment
		(start 305.744372 -231.896666)
		(end 305.744372 -231.941624)
		(width 0.18288)
		(layer "In11.Cu")
		(net "M_D_CPU0_SB_CB<3>")
	)
	(segment
		(start 286.594042 -231.789986)
		(end 286.594042 -231.339136)
		(width 0.18288)
		(layer "In11.Cu")
		(net "M_D_CPU0_SB_CB<3>")
	)
	(segment
		(start 331.308964 -240.263426)
		(end 321.163188 -240.263426)
		(width 0.18288)
		(layer "In11.Cu")
		(net "M_D_CPU0_SB_CB<3>")
	)
	(segment
		(start 305.937412 -231.703626)
		(end 305.744372 -231.896666)
		(width 0.18288)
		(layer "In11.Cu")
		(net "M_D_CPU0_SB_CB<3>")
	)
	(segment
		(start 276.604476 -234.3023)
		(end 273.434048 -234.3023)
		(width 0.18288)
		(layer "In11.Cu")
		(net "M_D_CPU0_SB_CB<3>")
	)
	(segment
		(start 288.838894 -231.627426)
		(end 288.483294 -231.983026)
		(width 0.18288)
		(layer "In11.Cu")
		(net "M_D_CPU0_SB_CB<3>")
	)
	(segment
		(start 347.83268 -243.108988)
		(end 347.520006 -243.108988)
		(width 0.088646)
		(layer "In11.Cu")
		(net "M_D_CPU0_SB_CB<3>")
	)
	(segment
		(start 285.893002 -231.789986)
		(end 285.699962 -231.983026)
		(width 0.18288)
		(layer "In11.Cu")
		(net "M_D_CPU0_SB_CB<3>")
	)
	(segment
		(start 338.166964 -242.61064)
		(end 338.152232 -242.619276)
		(width 0.088646)
		(layer "In11.Cu")
		(net "M_D_CPU0_SB_CB<3>")
	)
	(segment
		(start 285.893002 -231.339136)
		(end 285.893002 -231.789986)
		(width 0.18288)
		(layer "In11.Cu")
		(net "M_D_CPU0_SB_CB<3>")
	)
	(segment
		(start 342.865964 -242.61064)
		(end 342.851232 -242.619276)
		(width 0.088646)
		(layer "In11.Cu")
		(net "M_D_CPU0_SB_CB<3>")
	)
	(segment
		(start 299.748448 -231.74198)
		(end 297.970448 -231.74198)
		(width 0.18288)
		(layer "In11.Cu")
		(net "M_D_CPU0_SB_CB<3>")
	)
	(segment
		(start 311.083198 -232.866692)
		(end 310.80837 -232.591864)
		(width 0.18288)
		(layer "In11.Cu")
		(net "M_D_CPU0_SB_CB<3>")
	)
	(segment
		(start 284.71114 -231.741472)
		(end 283.098494 -231.741472)
		(width 0.18288)
		(layer "In11.Cu")
		(net "M_D_CPU0_SB_CB<3>")
	)
	(segment
		(start 312.374534 -232.866692)
		(end 311.083198 -232.866692)
		(width 0.18288)
		(layer "In11.Cu")
		(net "M_D_CPU0_SB_CB<3>")
	)
	(segment
		(start 291.175694 -232.618026)
		(end 290.185094 -231.627426)
		(width 0.18288)
		(layer "In11.Cu")
		(net "M_D_CPU0_SB_CB<3>")
	)
	(segment
		(start 309.234332 -232.591864)
		(end 308.625494 -231.983026)
		(width 0.18288)
		(layer "In11.Cu")
		(net "M_D_CPU0_SB_CB<3>")
	)
	(segment
		(start 321.163188 -240.263426)
		(end 315.860684 -234.960922)
		(width 0.18288)
		(layer "In11.Cu")
		(net "M_D_CPU0_SB_CB<3>")
	)
	(segment
		(start 296.584624 -231.424226)
		(end 295.416224 -232.592626)
		(width 0.18288)
		(layer "In11.Cu")
		(net "M_D_CPU0_SB_CB<3>")
	)
	(segment
		(start 288.483294 -231.983026)
		(end 286.787082 -231.983026)
		(width 0.18288)
		(layer "In11.Cu")
		(net "M_D_CPU0_SB_CB<3>")
	)
	(segment
		(start 297.970448 -231.74198)
		(end 297.652694 -231.424226)
		(width 0.18288)
		(layer "In11.Cu")
		(net "M_D_CPU0_SB_CB<3>")
	)
	(segment
		(start 305.236372 -232.134664)
		(end 305.043332 -231.941624)
		(width 0.18288)
		(layer "In11.Cu")
		(net "M_D_CPU0_SB_CB<3>")
	)
	(segment
		(start 277.277322 -233.629454)
		(end 276.604476 -234.3023)
		(width 0.18288)
		(layer "In11.Cu")
		(net "M_D_CPU0_SB_CB<3>")
	)
	(segment
		(start 286.086042 -231.146096)
		(end 285.893002 -231.339136)
		(width 0.18288)
		(layer "In11.Cu")
		(net "M_D_CPU0_SB_CB<3>")
	)
	(segment
		(start 285.699962 -231.983026)
		(end 284.952694 -231.983026)
		(width 0.18288)
		(layer "In11.Cu")
		(net "M_D_CPU0_SB_CB<3>")
	)
	(segment
		(start 295.416224 -232.592626)
		(end 294.426894 -232.592626)
		(width 0.18288)
		(layer "In11.Cu")
		(net "M_D_CPU0_SB_CB<3>")
	)
	(segment
		(start 307.660294 -231.983026)
		(end 307.380894 -231.703626)
		(width 0.18288)
		(layer "In11.Cu")
		(net "M_D_CPU0_SB_CB<3>")
	)
	(segment
		(start 294.426894 -232.592626)
		(end 294.096694 -232.262426)
		(width 0.18288)
		(layer "In11.Cu")
		(net "M_D_CPU0_SB_CB<3>")
	)
	(segment
		(start 281.498294 -231.576626)
		(end 280.483564 -232.591356)
		(width 0.18288)
		(layer "In11.Cu")
		(net "M_D_CPU0_SB_CB<3>")
	)
	(segment
		(start 286.594042 -231.339136)
		(end 286.401002 -231.146096)
		(width 0.18288)
		(layer "In11.Cu")
		(net "M_D_CPU0_SB_CB<3>")
	)
	(segment
		(start 304.850292 -231.703626)
		(end 303.748694 -231.703626)
		(width 0.18288)
		(layer "In11.Cu")
		(net "M_D_CPU0_SB_CB<3>")
	)
	(segment
		(start 294.096694 -232.262426)
		(end 292.166294 -232.262426)
		(width 0.18288)
		(layer "In11.Cu")
		(net "M_D_CPU0_SB_CB<3>")
	)
	(segment
		(start 305.043332 -231.896666)
		(end 304.850292 -231.703626)
		(width 0.18288)
		(layer "In11.Cu")
		(net "M_D_CPU0_SB_CB<3>")
	)
	(segment
		(start 284.952694 -231.983026)
		(end 284.71114 -231.741472)
		(width 0.18288)
		(layer "In11.Cu")
		(net "M_D_CPU0_SB_CB<3>")
	)
	(segment
		(start 290.185094 -231.627426)
		(end 288.838894 -231.627426)
		(width 0.18288)
		(layer "In11.Cu")
		(net "M_D_CPU0_SB_CB<3>")
	)
	(segment
		(start 286.787082 -231.983026)
		(end 286.594042 -231.789986)
		(width 0.18288)
		(layer "In11.Cu")
		(net "M_D_CPU0_SB_CB<3>")
	)
	(segment
		(start 336.287364 -242.61064)
		(end 336.272632 -242.619276)
		(width 0.088646)
		(layer "In11.Cu")
		(net "M_D_CPU0_SB_CB<3>")
	)
	(segment
		(start 307.380894 -231.703626)
		(end 305.937412 -231.703626)
		(width 0.18288)
		(layer "In11.Cu")
		(net "M_D_CPU0_SB_CB<3>")
	)
	(segment
		(start 334.770984 -242.303554)
		(end 334.770984 -242.285012)
		(width 0.088646)
		(layer "In11.Cu")
		(net "M_D_CPU0_SB_CB<3>")
	)
	(segment
		(start 305.744372 -231.941624)
		(end 305.551332 -232.134664)
		(width 0.18288)
		(layer "In11.Cu")
		(net "M_D_CPU0_SB_CB<3>")
	)
	(segment
		(start 303.545494 -231.906826)
		(end 299.913294 -231.906826)
		(width 0.18288)
		(layer "In11.Cu")
		(net "M_D_CPU0_SB_CB<3>")
	)
	(segment
		(start 292.166294 -232.262426)
		(end 291.810694 -232.618026)
		(width 0.18288)
		(layer "In11.Cu")
		(net "M_D_CPU0_SB_CB<3>")
	)
	(segment
		(start 341.926164 -242.61064)
		(end 341.911432 -242.619276)
		(width 0.088646)
		(layer "In11.Cu")
		(net "M_D_CPU0_SB_CB<3>")
	)
	(segment
		(start 286.401002 -231.146096)
		(end 286.086042 -231.146096)
		(width 0.18288)
		(layer "In11.Cu")
		(net "M_D_CPU0_SB_CB<3>")
	)
	(segment
		(start 337.227164 -242.61064)
		(end 337.212432 -242.619276)
		(width 0.088646)
		(layer "In11.Cu")
		(net "M_D_CPU0_SB_CB<3>")
	)
	(segment
		(start 343.805764 -242.61064)
		(end 343.791032 -242.619276)
		(width 0.088646)
		(layer "In11.Cu")
		(net "M_D_CPU0_SB_CB<3>")
	)
	(segment
		(start 269.441422 -233.628946)
		(end 268.829282 -233.016806)
		(width 0.18288)
		(layer "In11.Cu")
		(net "M_D_CPU0_SB_CB<3>")
	)
	(segment
		(start 278.969724 -232.591356)
		(end 277.931626 -233.629454)
		(width 0.18288)
		(layer "In11.Cu")
		(net "M_D_CPU0_SB_CB<3>")
	)
	(segment
		(start 299.913294 -231.906826)
		(end 299.748448 -231.74198)
		(width 0.18288)
		(layer "In11.Cu")
		(net "M_D_CPU0_SB_CB<3>")
	)
	(segment
		(start 331.71765 -240.424208)
		(end 331.556868 -240.263426)
		(width 0.088646)
		(layer "In11.Cu")
		(net "M_D_CPU0_SB_CB<3>")
	)
	(segment
		(start 314.010548 -234.502706)
		(end 312.374534 -232.866692)
		(width 0.18288)
		(layer "In11.Cu")
		(net "M_D_CPU0_SB_CB<3>")
	)
	(segment
		(start 280.483564 -232.591356)
		(end 278.969724 -232.591356)
		(width 0.18288)
		(layer "In11.Cu")
		(net "M_D_CPU0_SB_CB<3>")
	)
	(segment
		(start 272.760694 -233.628946)
		(end 269.441422 -233.628946)
		(width 0.18288)
		(layer "In11.Cu")
		(net "M_D_CPU0_SB_CB<3>")
	)
	(segment
		(start 331.71765 -240.93297)
		(end 331.71765 -240.424208)
		(width 0.088646)
		(layer "In11.Cu")
		(net "M_D_CPU0_SB_CB<3>")
	)
	(segment
		(start 314.754514 -234.502706)
		(end 314.010548 -234.502706)
		(width 0.18288)
		(layer "In11.Cu")
		(net "M_D_CPU0_SB_CB<3>")
	)
	(segment
		(start 331.556868 -240.263426)
		(end 331.308964 -240.263426)
		(width 0.088646)
		(layer "In11.Cu")
		(net "M_D_CPU0_SB_CB<3>")
	)
	(segment
		(start 308.625494 -231.983026)
		(end 307.660294 -231.983026)
		(width 0.18288)
		(layer "In11.Cu")
		(net "M_D_CPU0_SB_CB<3>")
	)
	(segment
		(start 347.520006 -243.108988)
		(end 347.454728 -243.04371)
		(width 0.088646)
		(layer "In11.Cu")
		(net "M_D_CPU0_SB_CB<3>")
	)
	(segment
		(start 310.80837 -232.591864)
		(end 309.234332 -232.591864)
		(width 0.18288)
		(layer "In11.Cu")
		(net "M_D_CPU0_SB_CB<3>")
	)
	(segment
		(start 344.745564 -242.61064)
		(end 344.730832 -242.619276)
		(width 0.088646)
		(layer "In11.Cu")
		(net "M_D_CPU0_SB_CB<3>")
	)
	(segment
		(start 273.434048 -234.3023)
		(end 272.760694 -233.628946)
		(width 0.18288)
		(layer "In11.Cu")
		(net "M_D_CPU0_SB_CB<3>")
	)
	(segment
		(start 336.272632 -242.619276)
		(end 336.26425 -242.624102)
		(width 0.088646)
		(layer "In11.Cu")
		(net "M_D_CPU0_SB_CB<3>")
	)
	(segment
		(start 332.530958 -241.746278)
		(end 331.71765 -240.93297)
		(width 0.088646)
		(layer "In11.Cu")
		(net "M_D_CPU0_SB_CB<3>")
	)
	(segment
		(start 303.748694 -231.703626)
		(end 303.545494 -231.906826)
		(width 0.18288)
		(layer "In11.Cu")
		(net "M_D_CPU0_SB_CB<3>")
	)
	(segment
		(start 305.043332 -231.941624)
		(end 305.043332 -231.896666)
		(width 0.18288)
		(layer "In11.Cu")
		(net "M_D_CPU0_SB_CB<3>")
	)
	(segment
		(start 282.933648 -231.576626)
		(end 281.498294 -231.576626)
		(width 0.18288)
		(layer "In11.Cu")
		(net "M_D_CPU0_SB_CB<3>")
	)
	(segment
		(start 283.098494 -231.741472)
		(end 282.933648 -231.576626)
		(width 0.18288)
		(layer "In11.Cu")
		(net "M_D_CPU0_SB_CB<3>")
	)
	(arc
		(start 342.476836 -242.619276)
		(mid 342.202607 -242.543351)
		(end 341.926164 -242.61064)
		(width 0.088646)
		(layer "In11.Cu")
		(net "M_D_CPU0_SB_CB<3>")
	)
	(arc
		(start 334.770984 -242.285012)
		(mid 334.692873 -242.008063)
		(end 334.488536 -241.80546)
		(width 0.088646)
		(layer "In11.Cu")
		(net "M_D_CPU0_SB_CB<3>")
	)
	(arc
		(start 339.092032 -242.619276)
		(mid 338.904834 -242.669419)
		(end 338.717636 -242.619276)
		(width 0.088646)
		(layer "In11.Cu")
		(net "M_D_CPU0_SB_CB<3>")
	)
	(arc
		(start 340.971632 -242.619276)
		(mid 340.784434 -242.669419)
		(end 340.597236 -242.619276)
		(width 0.088646)
		(layer "In11.Cu")
		(net "M_D_CPU0_SB_CB<3>")
	)
	(arc
		(start 339.657436 -242.619276)
		(mid 339.374734 -242.543534)
		(end 339.092032 -242.619276)
		(width 0.088646)
		(layer "In11.Cu")
		(net "M_D_CPU0_SB_CB<3>")
	)
	(arc
		(start 333.548736 -241.80546)
		(mid 333.274537 -241.729625)
		(end 332.998064 -241.796824)
		(width 0.088646)
		(layer "In11.Cu")
		(net "M_D_CPU0_SB_CB<3>")
	)
	(arc
		(start 343.416636 -242.619276)
		(mid 343.142407 -242.543351)
		(end 342.865964 -242.61064)
		(width 0.088646)
		(layer "In11.Cu")
		(net "M_D_CPU0_SB_CB<3>")
	)
	(arc
		(start 344.730832 -242.619276)
		(mid 344.543634 -242.669419)
		(end 344.356436 -242.619276)
		(width 0.088646)
		(layer "In11.Cu")
		(net "M_D_CPU0_SB_CB<3>")
	)
	(arc
		(start 332.608936 -241.80546)
		(mid 332.568006 -241.778427)
		(end 332.530958 -241.746278)
		(width 0.088646)
		(layer "In11.Cu")
		(net "M_D_CPU0_SB_CB<3>")
	)
	(arc
		(start 336.838036 -242.619276)
		(mid 336.563807 -242.543351)
		(end 336.287364 -242.61064)
		(width 0.088646)
		(layer "In11.Cu")
		(net "M_D_CPU0_SB_CB<3>")
	)
	(arc
		(start 341.911432 -242.619276)
		(mid 341.724234 -242.669419)
		(end 341.537036 -242.619276)
		(width 0.088646)
		(layer "In11.Cu")
		(net "M_D_CPU0_SB_CB<3>")
	)
	(arc
		(start 336.26425 -242.624102)
		(mid 336.080742 -242.66938)
		(end 335.89849 -242.619276)
		(width 0.088646)
		(layer "In11.Cu")
		(net "M_D_CPU0_SB_CB<3>")
	)
	(arc
		(start 338.717636 -242.619276)
		(mid 338.443407 -242.543351)
		(end 338.166964 -242.61064)
		(width 0.088646)
		(layer "In11.Cu")
		(net "M_D_CPU0_SB_CB<3>")
	)
	(arc
		(start 341.537036 -242.619276)
		(mid 341.262807 -242.543351)
		(end 340.986364 -242.61064)
		(width 0.088646)
		(layer "In11.Cu")
		(net "M_D_CPU0_SB_CB<3>")
	)
	(arc
		(start 342.851232 -242.619276)
		(mid 342.664034 -242.669419)
		(end 342.476836 -242.619276)
		(width 0.088646)
		(layer "In11.Cu")
		(net "M_D_CPU0_SB_CB<3>")
	)
	(arc
		(start 333.923132 -241.80546)
		(mid 333.735934 -241.855603)
		(end 333.548736 -241.80546)
		(width 0.088646)
		(layer "In11.Cu")
		(net "M_D_CPU0_SB_CB<3>")
	)
	(arc
		(start 346.610432 -242.619276)
		(mid 346.423234 -242.669419)
		(end 346.236036 -242.619276)
		(width 0.088646)
		(layer "In11.Cu")
		(net "M_D_CPU0_SB_CB<3>")
	)
	(arc
		(start 346.236036 -242.619276)
		(mid 345.953334 -242.543534)
		(end 345.670632 -242.619276)
		(width 0.088646)
		(layer "In11.Cu")
		(net "M_D_CPU0_SB_CB<3>")
	)
	(arc
		(start 337.212432 -242.619276)
		(mid 337.025234 -242.669419)
		(end 336.838036 -242.619276)
		(width 0.088646)
		(layer "In11.Cu")
		(net "M_D_CPU0_SB_CB<3>")
	)
	(arc
		(start 347.175836 -242.619276)
		(mid 346.901607 -242.543351)
		(end 346.625164 -242.61064)
		(width 0.088646)
		(layer "In11.Cu")
		(net "M_D_CPU0_SB_CB<3>")
	)
	(arc
		(start 337.777836 -242.619276)
		(mid 337.503607 -242.543351)
		(end 337.227164 -242.61064)
		(width 0.088646)
		(layer "In11.Cu")
		(net "M_D_CPU0_SB_CB<3>")
	)
	(arc
		(start 345.296236 -242.619276)
		(mid 345.022007 -242.543351)
		(end 344.745564 -242.61064)
		(width 0.088646)
		(layer "In11.Cu")
		(net "M_D_CPU0_SB_CB<3>")
	)
	(arc
		(start 338.152232 -242.619276)
		(mid 337.965034 -242.669419)
		(end 337.777836 -242.619276)
		(width 0.088646)
		(layer "In11.Cu")
		(net "M_D_CPU0_SB_CB<3>")
	)
	(arc
		(start 335.89849 -242.619276)
		(mid 335.615534 -242.543407)
		(end 335.332578 -242.619276)
		(width 0.088646)
		(layer "In11.Cu")
		(net "M_D_CPU0_SB_CB<3>")
	)
	(arc
		(start 334.958182 -242.619276)
		(mid 334.823249 -242.485922)
		(end 334.770984 -242.303554)
		(width 0.088646)
		(layer "In11.Cu")
		(net "M_D_CPU0_SB_CB<3>")
	)
	(arc
		(start 340.597236 -242.619276)
		(mid 340.323007 -242.543351)
		(end 340.046564 -242.61064)
		(width 0.088646)
		(layer "In11.Cu")
		(net "M_D_CPU0_SB_CB<3>")
	)
	(arc
		(start 340.031832 -242.619276)
		(mid 339.844634 -242.669419)
		(end 339.657436 -242.619276)
		(width 0.088646)
		(layer "In11.Cu")
		(net "M_D_CPU0_SB_CB<3>")
	)
	(arc
		(start 343.791032 -242.619276)
		(mid 343.603834 -242.669419)
		(end 343.416636 -242.619276)
		(width 0.088646)
		(layer "In11.Cu")
		(net "M_D_CPU0_SB_CB<3>")
	)
	(arc
		(start 335.332578 -242.619276)
		(mid 335.14538 -242.669419)
		(end 334.958182 -242.619276)
		(width 0.088646)
		(layer "In11.Cu")
		(net "M_D_CPU0_SB_CB<3>")
	)
	(arc
		(start 332.983332 -241.80546)
		(mid 332.796134 -241.855603)
		(end 332.608936 -241.80546)
		(width 0.088646)
		(layer "In11.Cu")
		(net "M_D_CPU0_SB_CB<3>")
	)
	(arc
		(start 345.670632 -242.619276)
		(mid 345.483434 -242.669419)
		(end 345.296236 -242.619276)
		(width 0.088646)
		(layer "In11.Cu")
		(net "M_D_CPU0_SB_CB<3>")
	)
	(arc
		(start 334.488536 -241.80546)
		(mid 334.205834 -241.729684)
		(end 333.923132 -241.80546)
		(width 0.088646)
		(layer "In11.Cu")
		(net "M_D_CPU0_SB_CB<3>")
	)
	(arc
		(start 347.454728 -243.04371)
		(mid 347.365614 -242.798413)
		(end 347.175836 -242.619276)
		(width 0.088646)
		(layer "In11.Cu")
		(net "M_D_CPU0_SB_CB<3>")
	)
	(arc
		(start 344.356436 -242.619276)
		(mid 344.082207 -242.543351)
		(end 343.805764 -242.61064)
		(width 0.088646)
		(layer "In11.Cu")
		(net "M_D_CPU0_SB_CB<3>")
	)
	(segment
		(start 261.327646 -234.716574)
		(end 260.180582 -234.716574)
		(width 0.20066)
		(layer "F.Cu")
		(net "M_D_CPU0_SB_CB<2>")
	)
	(segment
		(start 265.601958 -234.435396)
		(end 265.458194 -234.291632)
		(width 0.20066)
		(layer "F.Cu")
		(net "M_D_CPU0_SB_CB<2>")
	)
	(segment
		(start 266.197842 -234.92841)
		(end 265.769344 -234.92841)
		(width 0.20066)
		(layer "F.Cu")
		(net "M_D_CPU0_SB_CB<2>")
	)
	(segment
		(start 348.302834 -244.45849)
		(end 348.302834 -243.922804)
		(width 0.20066)
		(layer "F.Cu")
		(net "M_D_CPU0_SB_CB<2>")
	)
	(segment
		(start 262.50011 -234.281472)
		(end 261.762748 -234.281472)
		(width 0.20066)
		(layer "F.Cu")
		(net "M_D_CPU0_SB_CB<2>")
	)
	(segment
		(start 265.458194 -234.291632)
		(end 264.825226 -234.291632)
		(width 0.20066)
		(layer "F.Cu")
		(net "M_D_CPU0_SB_CB<2>")
	)
	(segment
		(start 348.30258 -244.458744)
		(end 348.302834 -244.45849)
		(width 0.20066)
		(layer "F.Cu")
		(net "M_D_CPU0_SB_CB<2>")
	)
	(segment
		(start 265.601958 -234.761024)
		(end 265.601958 -234.435396)
		(width 0.20066)
		(layer "F.Cu")
		(net "M_D_CPU0_SB_CB<2>")
	)
	(segment
		(start 265.769344 -234.92841)
		(end 265.601958 -234.761024)
		(width 0.20066)
		(layer "F.Cu")
		(net "M_D_CPU0_SB_CB<2>")
	)
	(segment
		(start 262.765286 -234.291632)
		(end 262.51027 -234.291632)
		(width 0.101854)
		(layer "F.Cu")
		(net "M_D_CPU0_SB_CB<2>")
	)
	(segment
		(start 267.724382 -234.716574)
		(end 266.409678 -234.716574)
		(width 0.20066)
		(layer "F.Cu")
		(net "M_D_CPU0_SB_CB<2>")
	)
	(segment
		(start 266.409678 -234.716574)
		(end 266.197842 -234.92841)
		(width 0.20066)
		(layer "F.Cu")
		(net "M_D_CPU0_SB_CB<2>")
	)
	(segment
		(start 264.825226 -234.291632)
		(end 262.765286 -234.291632)
		(width 0.1016)
		(layer "F.Cu")
		(net "M_D_CPU0_SB_CB<2>")
	)
	(segment
		(start 261.762748 -234.281472)
		(end 261.327646 -234.716574)
		(width 0.20066)
		(layer "F.Cu")
		(net "M_D_CPU0_SB_CB<2>")
	)
	(segment
		(start 268.829282 -234.716574)
		(end 267.724382 -234.716574)
		(width 0.20066)
		(layer "F.Cu")
		(net "M_D_CPU0_SB_CB<2>")
	)
	(segment
		(start 262.51027 -234.291632)
		(end 262.50011 -234.281472)
		(width 0.101854)
		(layer "F.Cu")
		(net "M_D_CPU0_SB_CB<2>")
	)
	(segment
		(start 316.170564 -236.708442)
		(end 314.658502 -236.082078)
		(width 0.18288)
		(layer "In11.Cu")
		(net "M_D_CPU0_SB_CB<2>")
	)
	(segment
		(start 293.817294 -234.142026)
		(end 292.03396 -234.142026)
		(width 0.18288)
		(layer "In11.Cu")
		(net "M_D_CPU0_SB_CB<2>")
	)
	(segment
		(start 289.489388 -233.253026)
		(end 288.686494 -233.253026)
		(width 0.18288)
		(layer "In11.Cu")
		(net "M_D_CPU0_SB_CB<2>")
	)
	(segment
		(start 305.805078 -233.547666)
		(end 305.805078 -233.74604)
		(width 0.18288)
		(layer "In11.Cu")
		(net "M_D_CPU0_SB_CB<2>")
	)
	(segment
		(start 273.381978 -236.00791)
		(end 272.684494 -235.310426)
		(width 0.18288)
		(layer "In11.Cu")
		(net "M_D_CPU0_SB_CB<2>")
	)
	(segment
		(start 305.612038 -233.93908)
		(end 305.297078 -233.93908)
		(width 0.18288)
		(layer "In11.Cu")
		(net "M_D_CPU0_SB_CB<2>")
	)
	(segment
		(start 345.766136 -243.433346)
		(end 345.755722 -243.42725)
		(width 0.088646)
		(layer "In11.Cu")
		(net "M_D_CPU0_SB_CB<2>")
	)
	(segment
		(start 292.03396 -234.142026)
		(end 291.759894 -234.416092)
		(width 0.18288)
		(layer "In11.Cu")
		(net "M_D_CPU0_SB_CB<2>")
	)
	(segment
		(start 307.584856 -233.609388)
		(end 307.330094 -233.354626)
		(width 0.18288)
		(layer "In11.Cu")
		(net "M_D_CPU0_SB_CB<2>")
	)
	(segment
		(start 331.613764 -241.92992)
		(end 331.387196 -241.92992)
		(width 0.18288)
		(layer "In11.Cu")
		(net "M_D_CPU0_SB_CB<2>")
	)
	(segment
		(start 331.387196 -241.92992)
		(end 330.736702 -241.279426)
		(width 0.18288)
		(layer "In11.Cu")
		(net "M_D_CPU0_SB_CB<2>")
	)
	(segment
		(start 269.423134 -235.310426)
		(end 268.829282 -234.716574)
		(width 0.18288)
		(layer "In11.Cu")
		(net "M_D_CPU0_SB_CB<2>")
	)
	(segment
		(start 286.424878 -233.018838)
		(end 286.109918 -233.018838)
		(width 0.18288)
		(layer "In11.Cu")
		(net "M_D_CPU0_SB_CB<2>")
	)
	(segment
		(start 297.297094 -233.303826)
		(end 296.838878 -233.303826)
		(width 0.18288)
		(layer "In11.Cu")
		(net "M_D_CPU0_SB_CB<2>")
	)
	(segment
		(start 339.187536 -243.433346)
		(end 339.177122 -243.42725)
		(width 0.088646)
		(layer "In11.Cu")
		(net "M_D_CPU0_SB_CB<2>")
	)
	(segment
		(start 285.916878 -233.211878)
		(end 285.916878 -233.364786)
		(width 0.18288)
		(layer "In11.Cu")
		(net "M_D_CPU0_SB_CB<2>")
	)
	(segment
		(start 332.32598 -242.67033)
		(end 332.16469 -242.67033)
		(width 0.088646)
		(layer "In11.Cu")
		(net "M_D_CPU0_SB_CB<2>")
	)
	(segment
		(start 320.741548 -241.279426)
		(end 316.170564 -236.708442)
		(width 0.18288)
		(layer "In11.Cu")
		(net "M_D_CPU0_SB_CB<2>")
	)
	(segment
		(start 284.467046 -233.4387)
		(end 281.338274 -233.4387)
		(width 0.18288)
		(layer "In11.Cu")
		(net "M_D_CPU0_SB_CB<2>")
	)
	(segment
		(start 301.191168 -233.071924)
		(end 300.772322 -233.49077)
		(width 0.18288)
		(layer "In11.Cu")
		(net "M_D_CPU0_SB_CB<2>")
	)
	(segment
		(start 346.705682 -243.433346)
		(end 346.695268 -243.42725)
		(width 0.088646)
		(layer "In11.Cu")
		(net "M_D_CPU0_SB_CB<2>")
	)
	(segment
		(start 303.719484 -233.354626)
		(end 303.621694 -233.452416)
		(width 0.18288)
		(layer "In11.Cu")
		(net "M_D_CPU0_SB_CB<2>")
	)
	(segment
		(start 305.104038 -233.547666)
		(end 304.910998 -233.354626)
		(width 0.18288)
		(layer "In11.Cu")
		(net "M_D_CPU0_SB_CB<2>")
	)
	(segment
		(start 277.361142 -235.234226)
		(end 276.587458 -236.00791)
		(width 0.18288)
		(layer "In11.Cu")
		(net "M_D_CPU0_SB_CB<2>")
	)
	(segment
		(start 299.784262 -233.49077)
		(end 299.734986 -233.441494)
		(width 0.18288)
		(layer "In11.Cu")
		(net "M_D_CPU0_SB_CB<2>")
	)
	(segment
		(start 331.893164 -242.398804)
		(end 331.893164 -242.018566)
		(width 0.088646)
		(layer "In11.Cu")
		(net "M_D_CPU0_SB_CB<2>")
	)
	(segment
		(start 332.16469 -242.67033)
		(end 331.893164 -242.398804)
		(width 0.088646)
		(layer "In11.Cu")
		(net "M_D_CPU0_SB_CB<2>")
	)
	(segment
		(start 305.297078 -233.93908)
		(end 305.104038 -233.74604)
		(width 0.18288)
		(layer "In11.Cu")
		(net "M_D_CPU0_SB_CB<2>")
	)
	(segment
		(start 342.006682 -243.433346)
		(end 341.99195 -243.42471)
		(width 0.088646)
		(layer "In11.Cu")
		(net "M_D_CPU0_SB_CB<2>")
	)
	(segment
		(start 308.59857 -233.609388)
		(end 307.584856 -233.609388)
		(width 0.18288)
		(layer "In11.Cu")
		(net "M_D_CPU0_SB_CB<2>")
	)
	(segment
		(start 286.810958 -233.557826)
		(end 286.617918 -233.364786)
		(width 0.18288)
		(layer "In11.Cu")
		(net "M_D_CPU0_SB_CB<2>")
	)
	(segment
		(start 301.511716 -233.071924)
		(end 301.191168 -233.071924)
		(width 0.18288)
		(layer "In11.Cu")
		(net "M_D_CPU0_SB_CB<2>")
	)
	(segment
		(start 331.804518 -241.92992)
		(end 331.613764 -241.92992)
		(width 0.088646)
		(layer "In11.Cu")
		(net "M_D_CPU0_SB_CB<2>")
	)
	(segment
		(start 299.734986 -233.441494)
		(end 297.434762 -233.441494)
		(width 0.18288)
		(layer "In11.Cu")
		(net "M_D_CPU0_SB_CB<2>")
	)
	(segment
		(start 340.127082 -243.433346)
		(end 340.116668 -243.42725)
		(width 0.088646)
		(layer "In11.Cu")
		(net "M_D_CPU0_SB_CB<2>")
	)
	(segment
		(start 313.95416 -236.082078)
		(end 312.186574 -234.314492)
		(width 0.18288)
		(layer "In11.Cu")
		(net "M_D_CPU0_SB_CB<2>")
	)
	(segment
		(start 304.910998 -233.354626)
		(end 303.719484 -233.354626)
		(width 0.18288)
		(layer "In11.Cu")
		(net "M_D_CPU0_SB_CB<2>")
	)
	(segment
		(start 278.399494 -235.234226)
		(end 277.361142 -235.234226)
		(width 0.18288)
		(layer "In11.Cu")
		(net "M_D_CPU0_SB_CB<2>")
	)
	(segment
		(start 344.826082 -243.433346)
		(end 344.81135 -243.42471)
		(width 0.088646)
		(layer "In11.Cu")
		(net "M_D_CPU0_SB_CB<2>")
	)
	(segment
		(start 285.916878 -233.364786)
		(end 285.723838 -233.557826)
		(width 0.18288)
		(layer "In11.Cu")
		(net "M_D_CPU0_SB_CB<2>")
	)
	(segment
		(start 330.736702 -241.279426)
		(end 320.741548 -241.279426)
		(width 0.18288)
		(layer "In11.Cu")
		(net "M_D_CPU0_SB_CB<2>")
	)
	(segment
		(start 285.723838 -233.557826)
		(end 284.586172 -233.557826)
		(width 0.18288)
		(layer "In11.Cu")
		(net "M_D_CPU0_SB_CB<2>")
	)
	(segment
		(start 297.434762 -233.441494)
		(end 297.297094 -233.303826)
		(width 0.18288)
		(layer "In11.Cu")
		(net "M_D_CPU0_SB_CB<2>")
	)
	(segment
		(start 334.488536 -243.433346)
		(end 334.479646 -243.428266)
		(width 0.088646)
		(layer "In11.Cu")
		(net "M_D_CPU0_SB_CB<2>")
	)
	(segment
		(start 311.108598 -234.314492)
		(end 310.836818 -234.042712)
		(width 0.18288)
		(layer "In11.Cu")
		(net "M_D_CPU0_SB_CB<2>")
	)
	(segment
		(start 276.587458 -236.00791)
		(end 273.381978 -236.00791)
		(width 0.18288)
		(layer "In11.Cu")
		(net "M_D_CPU0_SB_CB<2>")
	)
	(segment
		(start 272.684494 -235.310426)
		(end 269.423134 -235.310426)
		(width 0.18288)
		(layer "In11.Cu")
		(net "M_D_CPU0_SB_CB<2>")
	)
	(segment
		(start 334.877664 -243.42471)
		(end 334.862932 -243.433346)
		(width 0.088646)
		(layer "In11.Cu")
		(net "M_D_CPU0_SB_CB<2>")
	)
	(segment
		(start 338.247482 -243.433346)
		(end 338.23275 -243.42471)
		(width 0.088646)
		(layer "In11.Cu")
		(net "M_D_CPU0_SB_CB<2>")
	)
	(segment
		(start 301.892208 -233.452416)
		(end 301.511716 -233.071924)
		(width 0.18288)
		(layer "In11.Cu")
		(net "M_D_CPU0_SB_CB<2>")
	)
	(segment
		(start 295.696894 -234.291632)
		(end 293.9669 -234.291632)
		(width 0.18288)
		(layer "In11.Cu")
		(net "M_D_CPU0_SB_CB<2>")
	)
	(segment
		(start 293.9669 -234.291632)
		(end 293.817294 -234.142026)
		(width 0.18288)
		(layer "In11.Cu")
		(net "M_D_CPU0_SB_CB<2>")
	)
	(segment
		(start 286.109918 -233.018838)
		(end 285.916878 -233.211878)
		(width 0.18288)
		(layer "In11.Cu")
		(net "M_D_CPU0_SB_CB<2>")
	)
	(segment
		(start 310.836818 -234.042712)
		(end 309.031894 -234.042712)
		(width 0.18288)
		(layer "In11.Cu")
		(net "M_D_CPU0_SB_CB<2>")
	)
	(segment
		(start 288.381694 -233.557826)
		(end 286.810958 -233.557826)
		(width 0.18288)
		(layer "In11.Cu")
		(net "M_D_CPU0_SB_CB<2>")
	)
	(segment
		(start 314.658502 -236.082078)
		(end 313.95416 -236.082078)
		(width 0.18288)
		(layer "In11.Cu")
		(net "M_D_CPU0_SB_CB<2>")
	)
	(segment
		(start 307.330094 -233.354626)
		(end 305.998118 -233.354626)
		(width 0.18288)
		(layer "In11.Cu")
		(net "M_D_CPU0_SB_CB<2>")
	)
	(segment
		(start 333.078582 -242.619276)
		(end 333.06385 -242.61064)
		(width 0.088646)
		(layer "In11.Cu")
		(net "M_D_CPU0_SB_CB<2>")
	)
	(segment
		(start 334.301084 -243.108988)
		(end 334.301084 -243.090446)
		(width 0.088646)
		(layer "In11.Cu")
		(net "M_D_CPU0_SB_CB<2>")
	)
	(segment
		(start 312.186574 -234.314492)
		(end 311.108598 -234.314492)
		(width 0.18288)
		(layer "In11.Cu")
		(net "M_D_CPU0_SB_CB<2>")
	)
	(segment
		(start 305.998118 -233.354626)
		(end 305.805078 -233.547666)
		(width 0.18288)
		(layer "In11.Cu")
		(net "M_D_CPU0_SB_CB<2>")
	)
	(segment
		(start 305.104038 -233.74604)
		(end 305.104038 -233.547666)
		(width 0.18288)
		(layer "In11.Cu")
		(net "M_D_CPU0_SB_CB<2>")
	)
	(segment
		(start 337.307682 -243.433346)
		(end 337.29295 -243.42471)
		(width 0.088646)
		(layer "In11.Cu")
		(net "M_D_CPU0_SB_CB<2>")
	)
	(segment
		(start 296.838878 -233.303826)
		(end 296.575734 -233.412792)
		(width 0.18288)
		(layer "In11.Cu")
		(net "M_D_CPU0_SB_CB<2>")
	)
	(segment
		(start 343.886282 -243.433346)
		(end 343.87155 -243.42471)
		(width 0.088646)
		(layer "In11.Cu")
		(net "M_D_CPU0_SB_CB<2>")
	)
	(segment
		(start 291.759894 -234.416092)
		(end 290.652454 -234.416092)
		(width 0.18288)
		(layer "In11.Cu")
		(net "M_D_CPU0_SB_CB<2>")
	)
	(segment
		(start 347.999558 -243.786914)
		(end 347.784928 -243.54663)
		(width 0.088646)
		(layer "In11.Cu")
		(net "M_D_CPU0_SB_CB<2>")
	)
	(segment
		(start 286.617918 -233.364786)
		(end 286.617918 -233.211878)
		(width 0.18288)
		(layer "In11.Cu")
		(net "M_D_CPU0_SB_CB<2>")
	)
	(segment
		(start 336.367882 -243.433346)
		(end 336.357468 -243.42725)
		(width 0.088646)
		(layer "In11.Cu")
		(net "M_D_CPU0_SB_CB<2>")
	)
	(segment
		(start 305.805078 -233.74604)
		(end 305.612038 -233.93908)
		(width 0.18288)
		(layer "In11.Cu")
		(net "M_D_CPU0_SB_CB<2>")
	)
	(segment
		(start 300.772322 -233.49077)
		(end 299.784262 -233.49077)
		(width 0.18288)
		(layer "In11.Cu")
		(net "M_D_CPU0_SB_CB<2>")
	)
	(segment
		(start 341.066882 -243.433346)
		(end 341.05215 -243.42471)
		(width 0.088646)
		(layer "In11.Cu")
		(net "M_D_CPU0_SB_CB<2>")
	)
	(segment
		(start 279.342088 -234.291632)
		(end 278.399494 -235.234226)
		(width 0.18288)
		(layer "In11.Cu")
		(net "M_D_CPU0_SB_CB<2>")
	)
	(segment
		(start 309.031894 -234.042712)
		(end 308.59857 -233.609388)
		(width 0.18288)
		(layer "In11.Cu")
		(net "M_D_CPU0_SB_CB<2>")
	)
	(segment
		(start 303.621694 -233.452416)
		(end 301.892208 -233.452416)
		(width 0.18288)
		(layer "In11.Cu")
		(net "M_D_CPU0_SB_CB<2>")
	)
	(segment
		(start 286.617918 -233.211878)
		(end 286.424878 -233.018838)
		(width 0.18288)
		(layer "In11.Cu")
		(net "M_D_CPU0_SB_CB<2>")
	)
	(segment
		(start 290.652454 -234.416092)
		(end 289.489388 -233.253026)
		(width 0.18288)
		(layer "In11.Cu")
		(net "M_D_CPU0_SB_CB<2>")
	)
	(segment
		(start 284.586172 -233.557826)
		(end 284.467046 -233.4387)
		(width 0.18288)
		(layer "In11.Cu")
		(net "M_D_CPU0_SB_CB<2>")
	)
	(segment
		(start 281.338274 -233.4387)
		(end 280.485342 -234.291632)
		(width 0.18288)
		(layer "In11.Cu")
		(net "M_D_CPU0_SB_CB<2>")
	)
	(segment
		(start 334.018636 -242.619276)
		(end 334.008222 -242.61318)
		(width 0.088646)
		(layer "In11.Cu")
		(net "M_D_CPU0_SB_CB<2>")
	)
	(segment
		(start 296.575734 -233.412792)
		(end 295.696894 -234.291632)
		(width 0.18288)
		(layer "In11.Cu")
		(net "M_D_CPU0_SB_CB<2>")
	)
	(segment
		(start 331.893164 -242.018566)
		(end 331.804518 -241.92992)
		(width 0.088646)
		(layer "In11.Cu")
		(net "M_D_CPU0_SB_CB<2>")
	)
	(segment
		(start 288.686494 -233.253026)
		(end 288.381694 -233.557826)
		(width 0.18288)
		(layer "In11.Cu")
		(net "M_D_CPU0_SB_CB<2>")
	)
	(segment
		(start 280.485342 -234.291632)
		(end 279.342088 -234.291632)
		(width 0.18288)
		(layer "In11.Cu")
		(net "M_D_CPU0_SB_CB<2>")
	)
	(arc
		(start 344.81135 -243.42471)
		(mid 344.534875 -243.35739)
		(end 344.260678 -243.433346)
		(width 0.088646)
		(layer "In11.Cu")
		(net "M_D_CPU0_SB_CB<2>")
	)
	(arc
		(start 335.428336 -243.433346)
		(mid 335.154137 -243.357511)
		(end 334.877664 -243.42471)
		(width 0.088646)
		(layer "In11.Cu")
		(net "M_D_CPU0_SB_CB<2>")
	)
	(arc
		(start 346.695268 -243.42725)
		(mid 346.41709 -243.357527)
		(end 346.140532 -243.433346)
		(width 0.088646)
		(layer "In11.Cu")
		(net "M_D_CPU0_SB_CB<2>")
	)
	(arc
		(start 333.06385 -242.61064)
		(mid 332.787409 -242.543474)
		(end 332.513178 -242.619276)
		(width 0.088646)
		(layer "In11.Cu")
		(net "M_D_CPU0_SB_CB<2>")
	)
	(arc
		(start 341.05215 -243.42471)
		(mid 340.775675 -243.35739)
		(end 340.501478 -243.433346)
		(width 0.088646)
		(layer "In11.Cu")
		(net "M_D_CPU0_SB_CB<2>")
	)
	(arc
		(start 347.080078 -243.433346)
		(mid 346.89288 -243.483489)
		(end 346.705682 -243.433346)
		(width 0.088646)
		(layer "In11.Cu")
		(net "M_D_CPU0_SB_CB<2>")
	)
	(arc
		(start 341.441278 -243.433346)
		(mid 341.25408 -243.483489)
		(end 341.066882 -243.433346)
		(width 0.088646)
		(layer "In11.Cu")
		(net "M_D_CPU0_SB_CB<2>")
	)
	(arc
		(start 337.682078 -243.433346)
		(mid 337.49488 -243.483489)
		(end 337.307682 -243.433346)
		(width 0.088646)
		(layer "In11.Cu")
		(net "M_D_CPU0_SB_CB<2>")
	)
	(arc
		(start 341.99195 -243.42471)
		(mid 341.715475 -243.35739)
		(end 341.441278 -243.433346)
		(width 0.088646)
		(layer "In11.Cu")
		(net "M_D_CPU0_SB_CB<2>")
	)
	(arc
		(start 343.87155 -243.42471)
		(mid 343.595075 -243.35739)
		(end 343.320878 -243.433346)
		(width 0.088646)
		(layer "In11.Cu")
		(net "M_D_CPU0_SB_CB<2>")
	)
	(arc
		(start 336.357468 -243.42725)
		(mid 336.07929 -243.357527)
		(end 335.802732 -243.433346)
		(width 0.088646)
		(layer "In11.Cu")
		(net "M_D_CPU0_SB_CB<2>")
	)
	(arc
		(start 333.452978 -242.619276)
		(mid 333.26578 -242.669419)
		(end 333.078582 -242.619276)
		(width 0.088646)
		(layer "In11.Cu")
		(net "M_D_CPU0_SB_CB<2>")
	)
	(arc
		(start 338.23275 -243.42471)
		(mid 337.956275 -243.35739)
		(end 337.682078 -243.433346)
		(width 0.088646)
		(layer "In11.Cu")
		(net "M_D_CPU0_SB_CB<2>")
	)
	(arc
		(start 343.320878 -243.433346)
		(mid 343.13368 -243.483489)
		(end 342.946482 -243.433346)
		(width 0.088646)
		(layer "In11.Cu")
		(net "M_D_CPU0_SB_CB<2>")
	)
	(arc
		(start 347.784928 -243.54663)
		(mid 347.722473 -243.486636)
		(end 347.651578 -243.436902)
		(width 0.088646)
		(layer "In11.Cu")
		(net "M_D_CPU0_SB_CB<2>")
	)
	(arc
		(start 334.008222 -242.61318)
		(mid 333.72979 -242.543366)
		(end 333.452978 -242.619276)
		(width 0.088646)
		(layer "In11.Cu")
		(net "M_D_CPU0_SB_CB<2>")
	)
	(arc
		(start 342.381078 -243.433346)
		(mid 342.19388 -243.483489)
		(end 342.006682 -243.433346)
		(width 0.088646)
		(layer "In11.Cu")
		(net "M_D_CPU0_SB_CB<2>")
	)
	(arc
		(start 345.755722 -243.42725)
		(mid 345.47729 -243.357404)
		(end 345.200478 -243.433346)
		(width 0.088646)
		(layer "In11.Cu")
		(net "M_D_CPU0_SB_CB<2>")
	)
	(arc
		(start 348.302834 -243.922804)
		(mid 348.13665 -243.887297)
		(end 347.999558 -243.786914)
		(width 0.088646)
		(layer "In11.Cu")
		(net "M_D_CPU0_SB_CB<2>")
	)
	(arc
		(start 344.260678 -243.433346)
		(mid 344.07348 -243.483489)
		(end 343.886282 -243.433346)
		(width 0.088646)
		(layer "In11.Cu")
		(net "M_D_CPU0_SB_CB<2>")
	)
	(arc
		(start 337.29295 -243.42471)
		(mid 337.016475 -243.35739)
		(end 336.742278 -243.433346)
		(width 0.088646)
		(layer "In11.Cu")
		(net "M_D_CPU0_SB_CB<2>")
	)
	(arc
		(start 342.946482 -243.433346)
		(mid 342.66378 -243.35757)
		(end 342.381078 -243.433346)
		(width 0.088646)
		(layer "In11.Cu")
		(net "M_D_CPU0_SB_CB<2>")
	)
	(arc
		(start 334.301084 -243.090446)
		(mid 334.220922 -242.818257)
		(end 334.018636 -242.619276)
		(width 0.088646)
		(layer "In11.Cu")
		(net "M_D_CPU0_SB_CB<2>")
	)
	(arc
		(start 339.561932 -243.433346)
		(mid 339.374734 -243.483489)
		(end 339.187536 -243.433346)
		(width 0.088646)
		(layer "In11.Cu")
		(net "M_D_CPU0_SB_CB<2>")
	)
	(arc
		(start 346.140532 -243.433346)
		(mid 345.953334 -243.483489)
		(end 345.766136 -243.433346)
		(width 0.088646)
		(layer "In11.Cu")
		(net "M_D_CPU0_SB_CB<2>")
	)
	(arc
		(start 345.200478 -243.433346)
		(mid 345.01328 -243.483489)
		(end 344.826082 -243.433346)
		(width 0.088646)
		(layer "In11.Cu")
		(net "M_D_CPU0_SB_CB<2>")
	)
	(arc
		(start 336.742278 -243.433346)
		(mid 336.55508 -243.483489)
		(end 336.367882 -243.433346)
		(width 0.088646)
		(layer "In11.Cu")
		(net "M_D_CPU0_SB_CB<2>")
	)
	(arc
		(start 334.479646 -243.428266)
		(mid 334.348732 -243.291906)
		(end 334.301084 -243.108988)
		(width 0.088646)
		(layer "In11.Cu")
		(net "M_D_CPU0_SB_CB<2>")
	)
	(arc
		(start 334.862932 -243.433346)
		(mid 334.675734 -243.483489)
		(end 334.488536 -243.433346)
		(width 0.088646)
		(layer "In11.Cu")
		(net "M_D_CPU0_SB_CB<2>")
	)
	(arc
		(start 339.177122 -243.42725)
		(mid 338.89869 -243.357404)
		(end 338.621878 -243.433346)
		(width 0.088646)
		(layer "In11.Cu")
		(net "M_D_CPU0_SB_CB<2>")
	)
	(arc
		(start 347.651578 -243.436902)
		(mid 347.366309 -243.357567)
		(end 347.080078 -243.433346)
		(width 0.088646)
		(layer "In11.Cu")
		(net "M_D_CPU0_SB_CB<2>")
	)
	(arc
		(start 340.501478 -243.433346)
		(mid 340.31428 -243.483489)
		(end 340.127082 -243.433346)
		(width 0.088646)
		(layer "In11.Cu")
		(net "M_D_CPU0_SB_CB<2>")
	)
	(arc
		(start 335.802732 -243.433346)
		(mid 335.615534 -243.483489)
		(end 335.428336 -243.433346)
		(width 0.088646)
		(layer "In11.Cu")
		(net "M_D_CPU0_SB_CB<2>")
	)
	(arc
		(start 338.621878 -243.433346)
		(mid 338.43468 -243.483489)
		(end 338.247482 -243.433346)
		(width 0.088646)
		(layer "In11.Cu")
		(net "M_D_CPU0_SB_CB<2>")
	)
	(arc
		(start 340.116668 -243.42725)
		(mid 339.83849 -243.357527)
		(end 339.561932 -243.433346)
		(width 0.088646)
		(layer "In11.Cu")
		(net "M_D_CPU0_SB_CB<2>")
	)
	(arc
		(start 332.513178 -242.619276)
		(mid 332.422942 -242.657146)
		(end 332.32598 -242.67033)
		(width 0.088646)
		(layer "In11.Cu")
		(net "M_D_CPU0_SB_CB<2>")
	)
	(segment
		(start 346.893134 -243.644928)
		(end 346.89288 -243.644674)
		(width 0.20066)
		(layer "F.Cu")
		(net "M_D_CPU0_SB_CB<1>")
	)
	(segment
		(start 258.44754 -233.432858)
		(end 258.28498 -233.595418)
		(width 0.20066)
		(layer "F.Cu")
		(net "M_D_CPU0_SB_CB<1>")
	)
	(segment
		(start 257.414776 -233.86669)
		(end 256.080514 -233.86669)
		(width 0.20066)
		(layer "F.Cu")
		(net "M_D_CPU0_SB_CB<1>")
	)
	(segment
		(start 257.626104 -234.078018)
		(end 257.414776 -233.86669)
		(width 0.20066)
		(layer "F.Cu")
		(net "M_D_CPU0_SB_CB<1>")
	)
	(segment
		(start 259.056378 -233.432858)
		(end 258.44754 -233.432858)
		(width 0.20066)
		(layer "F.Cu")
		(net "M_D_CPU0_SB_CB<1>")
	)
	(segment
		(start 263.624314 -233.86669)
		(end 261.984998 -233.86669)
		(width 0.20066)
		(layer "F.Cu")
		(net "M_D_CPU0_SB_CB<1>")
	)
	(segment
		(start 258.130548 -234.078018)
		(end 257.626104 -234.078018)
		(width 0.20066)
		(layer "F.Cu")
		(net "M_D_CPU0_SB_CB<1>")
	)
	(segment
		(start 261.984998 -233.86669)
		(end 261.560056 -233.441748)
		(width 0.20066)
		(layer "F.Cu")
		(net "M_D_CPU0_SB_CB<1>")
	)
	(segment
		(start 261.050786 -233.441748)
		(end 259.065268 -233.441748)
		(width 0.1016)
		(layer "F.Cu")
		(net "M_D_CPU0_SB_CB<1>")
	)
	(segment
		(start 261.381494 -233.441748)
		(end 261.050786 -233.441748)
		(width 0.101854)
		(layer "F.Cu")
		(net "M_D_CPU0_SB_CB<1>")
	)
	(segment
		(start 346.89288 -243.644674)
		(end 346.89288 -243.108988)
		(width 0.20066)
		(layer "F.Cu")
		(net "M_D_CPU0_SB_CB<1>")
	)
	(segment
		(start 259.065268 -233.441748)
		(end 259.056378 -233.432858)
		(width 0.1016)
		(layer "F.Cu")
		(net "M_D_CPU0_SB_CB<1>")
	)
	(segment
		(start 258.28498 -233.595418)
		(end 258.28498 -233.923586)
		(width 0.20066)
		(layer "F.Cu")
		(net "M_D_CPU0_SB_CB<1>")
	)
	(segment
		(start 264.729214 -233.86669)
		(end 263.624314 -233.86669)
		(width 0.20066)
		(layer "F.Cu")
		(net "M_D_CPU0_SB_CB<1>")
	)
	(segment
		(start 261.560056 -233.441748)
		(end 261.381494 -233.441748)
		(width 0.20066)
		(layer "F.Cu")
		(net "M_D_CPU0_SB_CB<1>")
	)
	(segment
		(start 258.28498 -233.923586)
		(end 258.130548 -234.078018)
		(width 0.20066)
		(layer "F.Cu")
		(net "M_D_CPU0_SB_CB<1>")
	)
	(segment
		(start 334.018636 -241.97056)
		(end 334.008222 -241.976656)
		(width 0.088646)
		(layer "In11.Cu")
		(net "M_D_CPU0_SB_CB<1>")
	)
	(segment
		(start 308.130194 -232.491026)
		(end 307.228494 -232.491026)
		(width 0.18288)
		(layer "In11.Cu")
		(net "M_D_CPU0_SB_CB<1>")
	)
	(segment
		(start 280.190194 -233.441494)
		(end 279.343866 -233.441494)
		(width 0.18288)
		(layer "In11.Cu")
		(net "M_D_CPU0_SB_CB<1>")
	)
	(segment
		(start 279.343866 -233.441494)
		(end 278.595074 -234.190286)
		(width 0.18288)
		(layer "In11.Cu")
		(net "M_D_CPU0_SB_CB<1>")
	)
	(segment
		(start 347.205554 -243.108988)
		(end 347.262958 -243.051584)
		(width 0.088646)
		(layer "In11.Cu")
		(net "M_D_CPU0_SB_CB<1>")
	)
	(segment
		(start 313.84113 -235.065062)
		(end 312.206894 -233.430826)
		(width 0.18288)
		(layer "In11.Cu")
		(net "M_D_CPU0_SB_CB<1>")
	)
	(segment
		(start 299.394372 -232.591864)
		(end 297.095164 -232.591864)
		(width 0.18288)
		(layer "In11.Cu")
		(net "M_D_CPU0_SB_CB<1>")
	)
	(segment
		(start 331.788262 -241.272822)
		(end 331.613764 -241.272822)
		(width 0.088646)
		(layer "In11.Cu")
		(net "M_D_CPU0_SB_CB<1>")
	)
	(segment
		(start 280.760678 -233.18851)
		(end 280.190194 -233.441494)
		(width 0.18288)
		(layer "In11.Cu")
		(net "M_D_CPU0_SB_CB<1>")
	)
	(segment
		(start 334.877664 -242.793266)
		(end 334.862932 -242.78463)
		(width 0.088646)
		(layer "In11.Cu")
		(net "M_D_CPU0_SB_CB<1>")
	)
	(segment
		(start 312.206894 -233.430826)
		(end 311.027064 -233.430826)
		(width 0.18288)
		(layer "In11.Cu")
		(net "M_D_CPU0_SB_CB<1>")
	)
	(segment
		(start 309.606442 -233.486706)
		(end 308.130194 -232.491026)
		(width 0.18288)
		(layer "In11.Cu")
		(net "M_D_CPU0_SB_CB<1>")
	)
	(segment
		(start 343.886282 -242.78463)
		(end 343.87155 -242.793266)
		(width 0.088646)
		(layer "In11.Cu")
		(net "M_D_CPU0_SB_CB<1>")
	)
	(segment
		(start 314.602622 -235.065062)
		(end 313.84113 -235.065062)
		(width 0.18288)
		(layer "In11.Cu")
		(net "M_D_CPU0_SB_CB<1>")
	)
	(segment
		(start 272.46199 -234.233466)
		(end 269.392654 -234.233466)
		(width 0.18288)
		(layer "In11.Cu")
		(net "M_D_CPU0_SB_CB<1>")
	)
	(segment
		(start 341.066882 -242.78463)
		(end 341.05215 -242.793266)
		(width 0.088646)
		(layer "In11.Cu")
		(net "M_D_CPU0_SB_CB<1>")
	)
	(segment
		(start 267.981938 -234.29087)
		(end 266.944094 -233.253026)
		(width 0.18288)
		(layer "In11.Cu")
		(net "M_D_CPU0_SB_CB<1>")
	)
	(segment
		(start 266.944094 -233.253026)
		(end 266.391644 -233.253026)
		(width 0.18288)
		(layer "In11.Cu")
		(net "M_D_CPU0_SB_CB<1>")
	)
	(segment
		(start 295.341294 -233.441494)
		(end 293.603426 -233.441494)
		(width 0.18288)
		(layer "In11.Cu")
		(net "M_D_CPU0_SB_CB<1>")
	)
	(segment
		(start 289.283394 -232.706926)
		(end 288.013394 -232.492042)
		(width 0.18288)
		(layer "In11.Cu")
		(net "M_D_CPU0_SB_CB<1>")
	)
	(segment
		(start 281.282648 -232.66654)
		(end 280.760678 -233.18851)
		(width 0.18288)
		(layer "In11.Cu")
		(net "M_D_CPU0_SB_CB<1>")
	)
	(segment
		(start 339.187536 -242.78463)
		(end 339.177122 -242.790726)
		(width 0.088646)
		(layer "In11.Cu")
		(net "M_D_CPU0_SB_CB<1>")
	)
	(segment
		(start 344.826082 -242.78463)
		(end 344.81135 -242.793266)
		(width 0.088646)
		(layer "In11.Cu")
		(net "M_D_CPU0_SB_CB<1>")
	)
	(segment
		(start 266.391644 -233.253026)
		(end 264.729214 -233.86669)
		(width 0.18288)
		(layer "In11.Cu")
		(net "M_D_CPU0_SB_CB<1>")
	)
	(segment
		(start 273.16557 -234.937046)
		(end 272.46199 -234.233466)
		(width 0.18288)
		(layer "In11.Cu")
		(net "M_D_CPU0_SB_CB<1>")
	)
	(segment
		(start 346.705682 -242.78463)
		(end 346.695268 -242.790726)
		(width 0.088646)
		(layer "In11.Cu")
		(net "M_D_CPU0_SB_CB<1>")
	)
	(segment
		(start 336.376518 -242.779804)
		(end 336.368136 -242.78463)
		(width 0.088646)
		(layer "In11.Cu")
		(net "M_D_CPU0_SB_CB<1>")
	)
	(segment
		(start 311.027064 -233.430826)
		(end 310.956198 -233.501692)
		(width 0.18288)
		(layer "In11.Cu")
		(net "M_D_CPU0_SB_CB<1>")
	)
	(segment
		(start 346.89288 -243.108988)
		(end 347.205554 -243.108988)
		(width 0.088646)
		(layer "In11.Cu")
		(net "M_D_CPU0_SB_CB<1>")
	)
	(segment
		(start 269.392654 -234.233466)
		(end 269.33525 -234.29087)
		(width 0.18288)
		(layer "In11.Cu")
		(net "M_D_CPU0_SB_CB<1>")
	)
	(segment
		(start 330.947522 -240.771426)
		(end 320.952368 -240.771426)
		(width 0.18288)
		(layer "In11.Cu")
		(net "M_D_CPU0_SB_CB<1>")
	)
	(segment
		(start 289.655758 -232.706926)
		(end 289.283394 -232.706926)
		(width 0.18288)
		(layer "In11.Cu")
		(net "M_D_CPU0_SB_CB<1>")
	)
	(segment
		(start 297.095164 -232.591864)
		(end 295.341294 -233.441494)
		(width 0.18288)
		(layer "In11.Cu")
		(net "M_D_CPU0_SB_CB<1>")
	)
	(segment
		(start 304.129694 -232.668826)
		(end 303.942242 -232.63606)
		(width 0.18288)
		(layer "In11.Cu")
		(net "M_D_CPU0_SB_CB<1>")
	)
	(segment
		(start 293.537894 -233.507026)
		(end 292.207442 -233.507026)
		(width 0.18288)
		(layer "In11.Cu")
		(net "M_D_CPU0_SB_CB<1>")
	)
	(segment
		(start 269.33525 -234.29087)
		(end 267.981938 -234.29087)
		(width 0.18288)
		(layer "In11.Cu")
		(net "M_D_CPU0_SB_CB<1>")
	)
	(segment
		(start 277.492714 -234.190286)
		(end 276.745954 -234.937046)
		(width 0.18288)
		(layer "In11.Cu")
		(net "M_D_CPU0_SB_CB<1>")
	)
	(segment
		(start 340.127082 -242.78463)
		(end 340.116668 -242.790726)
		(width 0.088646)
		(layer "In11.Cu")
		(net "M_D_CPU0_SB_CB<1>")
	)
	(segment
		(start 303.942242 -232.63606)
		(end 303.100994 -232.488486)
		(width 0.18288)
		(layer "In11.Cu")
		(net "M_D_CPU0_SB_CB<1>")
	)
	(segment
		(start 284.354778 -232.492042)
		(end 284.25521 -232.59161)
		(width 0.18288)
		(layer "In11.Cu")
		(net "M_D_CPU0_SB_CB<1>")
	)
	(segment
		(start 276.745954 -234.937046)
		(end 273.16557 -234.937046)
		(width 0.18288)
		(layer "In11.Cu")
		(net "M_D_CPU0_SB_CB<1>")
	)
	(segment
		(start 336.368136 -242.78463)
		(end 336.353404 -242.793266)
		(width 0.088646)
		(layer "In11.Cu")
		(net "M_D_CPU0_SB_CB<1>")
	)
	(segment
		(start 334.58023 -242.309142)
		(end 334.58023 -242.286282)
		(width 0.088646)
		(layer "In11.Cu")
		(net "M_D_CPU0_SB_CB<1>")
	)
	(segment
		(start 288.013394 -232.492042)
		(end 284.354778 -232.492042)
		(width 0.18288)
		(layer "In11.Cu")
		(net "M_D_CPU0_SB_CB<1>")
	)
	(segment
		(start 342.946482 -242.78463)
		(end 342.93175 -242.793266)
		(width 0.088646)
		(layer "In11.Cu")
		(net "M_D_CPU0_SB_CB<1>")
	)
	(segment
		(start 307.228494 -232.491026)
		(end 307.050694 -232.668826)
		(width 0.18288)
		(layer "In11.Cu")
		(net "M_D_CPU0_SB_CB<1>")
	)
	(segment
		(start 282.024836 -232.59161)
		(end 281.282648 -232.66654)
		(width 0.18288)
		(layer "In11.Cu")
		(net "M_D_CPU0_SB_CB<1>")
	)
	(segment
		(start 292.207442 -233.507026)
		(end 289.655758 -232.706926)
		(width 0.18288)
		(layer "In11.Cu")
		(net "M_D_CPU0_SB_CB<1>")
	)
	(segment
		(start 293.603426 -233.441494)
		(end 293.537894 -233.507026)
		(width 0.18288)
		(layer "In11.Cu")
		(net "M_D_CPU0_SB_CB<1>")
	)
	(segment
		(start 347.088968 -242.78971)
		(end 347.080078 -242.78463)
		(width 0.088646)
		(layer "In11.Cu")
		(net "M_D_CPU0_SB_CB<1>")
	)
	(segment
		(start 278.595074 -234.190286)
		(end 277.492714 -234.190286)
		(width 0.18288)
		(layer "In11.Cu")
		(net "M_D_CPU0_SB_CB<1>")
	)
	(segment
		(start 332.396338 -241.880898)
		(end 331.788262 -241.272822)
		(width 0.088646)
		(layer "In11.Cu")
		(net "M_D_CPU0_SB_CB<1>")
	)
	(segment
		(start 299.497496 -232.488486)
		(end 299.394372 -232.591864)
		(width 0.18288)
		(layer "In11.Cu")
		(net "M_D_CPU0_SB_CB<1>")
	)
	(segment
		(start 342.006682 -242.78463)
		(end 341.99195 -242.793266)
		(width 0.088646)
		(layer "In11.Cu")
		(net "M_D_CPU0_SB_CB<1>")
	)
	(segment
		(start 303.100994 -232.488486)
		(end 299.497496 -232.488486)
		(width 0.18288)
		(layer "In11.Cu")
		(net "M_D_CPU0_SB_CB<1>")
	)
	(segment
		(start 320.952368 -240.771426)
		(end 315.700918 -235.519976)
		(width 0.18288)
		(layer "In11.Cu")
		(net "M_D_CPU0_SB_CB<1>")
	)
	(segment
		(start 307.050694 -232.668826)
		(end 304.129694 -232.668826)
		(width 0.18288)
		(layer "In11.Cu")
		(net "M_D_CPU0_SB_CB<1>")
	)
	(segment
		(start 338.247482 -242.78463)
		(end 338.23275 -242.793266)
		(width 0.088646)
		(layer "In11.Cu")
		(net "M_D_CPU0_SB_CB<1>")
	)
	(segment
		(start 310.956198 -233.501692)
		(end 309.628794 -233.501692)
		(width 0.18288)
		(layer "In11.Cu")
		(net "M_D_CPU0_SB_CB<1>")
	)
	(segment
		(start 309.628794 -233.501692)
		(end 309.606442 -233.486706)
		(width 0.18288)
		(layer "In11.Cu")
		(net "M_D_CPU0_SB_CB<1>")
	)
	(segment
		(start 315.700918 -235.519976)
		(end 314.602622 -235.065062)
		(width 0.18288)
		(layer "In11.Cu")
		(net "M_D_CPU0_SB_CB<1>")
	)
	(segment
		(start 333.078582 -241.97056)
		(end 333.06385 -241.979196)
		(width 0.088646)
		(layer "In11.Cu")
		(net "M_D_CPU0_SB_CB<1>")
	)
	(segment
		(start 337.307682 -242.78463)
		(end 337.29295 -242.793266)
		(width 0.088646)
		(layer "In11.Cu")
		(net "M_D_CPU0_SB_CB<1>")
	)
	(segment
		(start 331.448918 -241.272822)
		(end 330.947522 -240.771426)
		(width 0.18288)
		(layer "In11.Cu")
		(net "M_D_CPU0_SB_CB<1>")
	)
	(segment
		(start 331.613764 -241.272822)
		(end 331.448918 -241.272822)
		(width 0.18288)
		(layer "In11.Cu")
		(net "M_D_CPU0_SB_CB<1>")
	)
	(segment
		(start 284.25521 -232.59161)
		(end 282.024836 -232.59161)
		(width 0.18288)
		(layer "In11.Cu")
		(net "M_D_CPU0_SB_CB<1>")
	)
	(segment
		(start 345.766136 -242.78463)
		(end 345.755722 -242.790726)
		(width 0.088646)
		(layer "In11.Cu")
		(net "M_D_CPU0_SB_CB<1>")
	)
	(arc
		(start 343.87155 -242.793266)
		(mid 343.595109 -242.860432)
		(end 343.320878 -242.78463)
		(width 0.088646)
		(layer "In11.Cu")
		(net "M_D_CPU0_SB_CB<1>")
	)
	(arc
		(start 333.452978 -241.97056)
		(mid 333.26578 -241.920417)
		(end 333.078582 -241.97056)
		(width 0.088646)
		(layer "In11.Cu")
		(net "M_D_CPU0_SB_CB<1>")
	)
	(arc
		(start 343.320878 -242.78463)
		(mid 343.13368 -242.734487)
		(end 342.946482 -242.78463)
		(width 0.088646)
		(layer "In11.Cu")
		(net "M_D_CPU0_SB_CB<1>")
	)
	(arc
		(start 341.99195 -242.793266)
		(mid 341.715509 -242.860432)
		(end 341.441278 -242.78463)
		(width 0.088646)
		(layer "In11.Cu")
		(net "M_D_CPU0_SB_CB<1>")
	)
	(arc
		(start 341.441278 -242.78463)
		(mid 341.25408 -242.734487)
		(end 341.066882 -242.78463)
		(width 0.088646)
		(layer "In11.Cu")
		(net "M_D_CPU0_SB_CB<1>")
	)
	(arc
		(start 337.682078 -242.78463)
		(mid 337.49488 -242.734487)
		(end 337.307682 -242.78463)
		(width 0.088646)
		(layer "In11.Cu")
		(net "M_D_CPU0_SB_CB<1>")
	)
	(arc
		(start 334.393032 -241.97056)
		(mid 334.205834 -241.920417)
		(end 334.018636 -241.97056)
		(width 0.088646)
		(layer "In11.Cu")
		(net "M_D_CPU0_SB_CB<1>")
	)
	(arc
		(start 347.262958 -243.051584)
		(mid 347.204802 -242.901471)
		(end 347.088968 -242.78971)
		(width 0.088646)
		(layer "In11.Cu")
		(net "M_D_CPU0_SB_CB<1>")
	)
	(arc
		(start 346.695268 -242.790726)
		(mid 346.41709 -242.860418)
		(end 346.140532 -242.78463)
		(width 0.088646)
		(layer "In11.Cu")
		(net "M_D_CPU0_SB_CB<1>")
	)
	(arc
		(start 335.802732 -242.78463)
		(mid 335.615534 -242.734487)
		(end 335.428336 -242.78463)
		(width 0.088646)
		(layer "In11.Cu")
		(net "M_D_CPU0_SB_CB<1>")
	)
	(arc
		(start 337.29295 -242.793266)
		(mid 337.016509 -242.860432)
		(end 336.742278 -242.78463)
		(width 0.088646)
		(layer "In11.Cu")
		(net "M_D_CPU0_SB_CB<1>")
	)
	(arc
		(start 336.742278 -242.78463)
		(mid 336.560027 -242.734519)
		(end 336.376518 -242.779804)
		(width 0.088646)
		(layer "In11.Cu")
		(net "M_D_CPU0_SB_CB<1>")
	)
	(arc
		(start 345.755722 -242.790726)
		(mid 345.47729 -242.86054)
		(end 345.200478 -242.78463)
		(width 0.088646)
		(layer "In11.Cu")
		(net "M_D_CPU0_SB_CB<1>")
	)
	(arc
		(start 342.381078 -242.78463)
		(mid 342.19388 -242.734487)
		(end 342.006682 -242.78463)
		(width 0.088646)
		(layer "In11.Cu")
		(net "M_D_CPU0_SB_CB<1>")
	)
	(arc
		(start 338.621878 -242.78463)
		(mid 338.43468 -242.734487)
		(end 338.247482 -242.78463)
		(width 0.088646)
		(layer "In11.Cu")
		(net "M_D_CPU0_SB_CB<1>")
	)
	(arc
		(start 335.428336 -242.78463)
		(mid 335.154107 -242.860555)
		(end 334.877664 -242.793266)
		(width 0.088646)
		(layer "In11.Cu")
		(net "M_D_CPU0_SB_CB<1>")
	)
	(arc
		(start 341.05215 -242.793266)
		(mid 340.775709 -242.860432)
		(end 340.501478 -242.78463)
		(width 0.088646)
		(layer "In11.Cu")
		(net "M_D_CPU0_SB_CB<1>")
	)
	(arc
		(start 339.177122 -242.790726)
		(mid 338.89869 -242.86054)
		(end 338.621878 -242.78463)
		(width 0.088646)
		(layer "In11.Cu")
		(net "M_D_CPU0_SB_CB<1>")
	)
	(arc
		(start 334.862932 -242.78463)
		(mid 334.659451 -242.583826)
		(end 334.58023 -242.309142)
		(width 0.088646)
		(layer "In11.Cu")
		(net "M_D_CPU0_SB_CB<1>")
	)
	(arc
		(start 344.260678 -242.78463)
		(mid 344.07348 -242.734487)
		(end 343.886282 -242.78463)
		(width 0.088646)
		(layer "In11.Cu")
		(net "M_D_CPU0_SB_CB<1>")
	)
	(arc
		(start 346.140532 -242.78463)
		(mid 345.953334 -242.734487)
		(end 345.766136 -242.78463)
		(width 0.088646)
		(layer "In11.Cu")
		(net "M_D_CPU0_SB_CB<1>")
	)
	(arc
		(start 340.116668 -242.790726)
		(mid 339.83849 -242.860418)
		(end 339.561932 -242.78463)
		(width 0.088646)
		(layer "In11.Cu")
		(net "M_D_CPU0_SB_CB<1>")
	)
	(arc
		(start 338.23275 -242.793266)
		(mid 337.956309 -242.860432)
		(end 337.682078 -242.78463)
		(width 0.088646)
		(layer "In11.Cu")
		(net "M_D_CPU0_SB_CB<1>")
	)
	(arc
		(start 334.008222 -241.976656)
		(mid 333.72979 -242.046502)
		(end 333.452978 -241.97056)
		(width 0.088646)
		(layer "In11.Cu")
		(net "M_D_CPU0_SB_CB<1>")
	)
	(arc
		(start 347.080078 -242.78463)
		(mid 346.89288 -242.734487)
		(end 346.705682 -242.78463)
		(width 0.088646)
		(layer "In11.Cu")
		(net "M_D_CPU0_SB_CB<1>")
	)
	(arc
		(start 342.93175 -242.793266)
		(mid 342.655309 -242.860432)
		(end 342.381078 -242.78463)
		(width 0.088646)
		(layer "In11.Cu")
		(net "M_D_CPU0_SB_CB<1>")
	)
	(arc
		(start 334.58023 -242.286282)
		(mid 334.52796 -242.103917)
		(end 334.393032 -241.97056)
		(width 0.088646)
		(layer "In11.Cu")
		(net "M_D_CPU0_SB_CB<1>")
	)
	(arc
		(start 333.06385 -241.979196)
		(mid 332.713806 -242.040558)
		(end 332.396338 -241.880898)
		(width 0.088646)
		(layer "In11.Cu")
		(net "M_D_CPU0_SB_CB<1>")
	)
	(arc
		(start 336.353404 -242.793266)
		(mid 336.076963 -242.860432)
		(end 335.802732 -242.78463)
		(width 0.088646)
		(layer "In11.Cu")
		(net "M_D_CPU0_SB_CB<1>")
	)
	(arc
		(start 345.200478 -242.78463)
		(mid 345.01328 -242.734487)
		(end 344.826082 -242.78463)
		(width 0.088646)
		(layer "In11.Cu")
		(net "M_D_CPU0_SB_CB<1>")
	)
	(arc
		(start 340.501478 -242.78463)
		(mid 340.31428 -242.734487)
		(end 340.127082 -242.78463)
		(width 0.088646)
		(layer "In11.Cu")
		(net "M_D_CPU0_SB_CB<1>")
	)
	(arc
		(start 339.561932 -242.78463)
		(mid 339.374734 -242.734487)
		(end 339.187536 -242.78463)
		(width 0.088646)
		(layer "In11.Cu")
		(net "M_D_CPU0_SB_CB<1>")
	)
	(arc
		(start 344.81135 -242.793266)
		(mid 344.534909 -242.860432)
		(end 344.260678 -242.78463)
		(width 0.088646)
		(layer "In11.Cu")
		(net "M_D_CPU0_SB_CB<1>")
	)
	(segment
		(start 258.28498 -235.343192)
		(end 258.28498 -235.632752)
		(width 0.20066)
		(layer "F.Cu")
		(net "M_D_CPU0_SB_CB<0>")
	)
	(segment
		(start 263.624314 -235.566712)
		(end 262.255254 -235.566712)
		(width 0.20066)
		(layer "F.Cu")
		(net "M_D_CPU0_SB_CB<0>")
	)
	(segment
		(start 346.423234 -244.45849)
		(end 346.423234 -243.922804)
		(width 0.20066)
		(layer "F.Cu")
		(net "M_D_CPU0_SB_CB<0>")
	)
	(segment
		(start 257.414776 -235.566712)
		(end 256.080514 -235.566712)
		(width 0.20066)
		(layer "F.Cu")
		(net "M_D_CPU0_SB_CB<0>")
	)
	(segment
		(start 258.11226 -235.805472)
		(end 257.653536 -235.805472)
		(width 0.20066)
		(layer "F.Cu")
		(net "M_D_CPU0_SB_CB<0>")
	)
	(segment
		(start 261.381494 -235.14177)
		(end 259.31241 -235.14177)
		(width 0.1016)
		(layer "F.Cu")
		(net "M_D_CPU0_SB_CB<0>")
	)
	(segment
		(start 264.729214 -235.566712)
		(end 263.624314 -235.566712)
		(width 0.20066)
		(layer "F.Cu")
		(net "M_D_CPU0_SB_CB<0>")
	)
	(segment
		(start 258.49453 -235.133642)
		(end 258.28498 -235.343192)
		(width 0.20066)
		(layer "F.Cu")
		(net "M_D_CPU0_SB_CB<0>")
	)
	(segment
		(start 259.056378 -235.133642)
		(end 258.49453 -235.133642)
		(width 0.20066)
		(layer "F.Cu")
		(net "M_D_CPU0_SB_CB<0>")
	)
	(segment
		(start 262.255254 -235.566712)
		(end 261.830312 -235.14177)
		(width 0.20066)
		(layer "F.Cu")
		(net "M_D_CPU0_SB_CB<0>")
	)
	(segment
		(start 259.064506 -235.14177)
		(end 259.056378 -235.133642)
		(width 0.101854)
		(layer "F.Cu")
		(net "M_D_CPU0_SB_CB<0>")
	)
	(segment
		(start 346.42298 -244.458744)
		(end 346.423234 -244.45849)
		(width 0.20066)
		(layer "F.Cu")
		(net "M_D_CPU0_SB_CB<0>")
	)
	(segment
		(start 259.31241 -235.14177)
		(end 259.064506 -235.14177)
		(width 0.101854)
		(layer "F.Cu")
		(net "M_D_CPU0_SB_CB<0>")
	)
	(segment
		(start 261.830312 -235.14177)
		(end 261.381494 -235.14177)
		(width 0.20066)
		(layer "F.Cu")
		(net "M_D_CPU0_SB_CB<0>")
	)
	(segment
		(start 257.653536 -235.805472)
		(end 257.414776 -235.566712)
		(width 0.20066)
		(layer "F.Cu")
		(net "M_D_CPU0_SB_CB<0>")
	)
	(segment
		(start 258.28498 -235.632752)
		(end 258.11226 -235.805472)
		(width 0.20066)
		(layer "F.Cu")
		(net "M_D_CPU0_SB_CB<0>")
	)
	(segment
		(start 296.961306 -234.669584)
		(end 296.245026 -234.669584)
		(width 0.18288)
		(layer "In11.Cu")
		(net "M_D_CPU0_SB_CB<0>")
	)
	(segment
		(start 306.796694 -234.472226)
		(end 303.92624 -234.472226)
		(width 0.18288)
		(layer "In11.Cu")
		(net "M_D_CPU0_SB_CB<0>")
	)
	(segment
		(start 298.949872 -234.291632)
		(end 297.339258 -234.291632)
		(width 0.18288)
		(layer "In11.Cu")
		(net "M_D_CPU0_SB_CB<0>")
	)
	(segment
		(start 288.514536 -234.396534)
		(end 288.273236 -234.155234)
		(width 0.18288)
		(layer "In11.Cu")
		(net "M_D_CPU0_SB_CB<0>")
	)
	(segment
		(start 312.002678 -234.91571)
		(end 310.93918 -234.91571)
		(width 0.18288)
		(layer "In11.Cu")
		(net "M_D_CPU0_SB_CB<0>")
	)
	(segment
		(start 277.662894 -235.742226)
		(end 276.863556 -236.541564)
		(width 0.18288)
		(layer "In11.Cu")
		(net "M_D_CPU0_SB_CB<0>")
	)
	(segment
		(start 273.179032 -236.541564)
		(end 272.466054 -235.828586)
		(width 0.18288)
		(layer "In11.Cu")
		(net "M_D_CPU0_SB_CB<0>")
	)
	(segment
		(start 284.733492 -234.155234)
		(end 284.597094 -234.291632)
		(width 0.18288)
		(layer "In11.Cu")
		(net "M_D_CPU0_SB_CB<0>")
	)
	(segment
		(start 331.613764 -242.440206)
		(end 331.178662 -242.440206)
		(width 0.18288)
		(layer "In11.Cu")
		(net "M_D_CPU0_SB_CB<0>")
	)
	(segment
		(start 334.110584 -243.124482)
		(end 334.110584 -243.108988)
		(width 0.088646)
		(layer "In11.Cu")
		(net "M_D_CPU0_SB_CB<0>")
	)
	(segment
		(start 292.059614 -235.000292)
		(end 290.255198 -235.000292)
		(width 0.18288)
		(layer "In11.Cu")
		(net "M_D_CPU0_SB_CB<0>")
	)
	(segment
		(start 338.166964 -243.607082)
		(end 338.152232 -243.598446)
		(width 0.088646)
		(layer "In11.Cu")
		(net "M_D_CPU0_SB_CB<0>")
	)
	(segment
		(start 268.35862 -235.990892)
		(end 267.068554 -234.700826)
		(width 0.18288)
		(layer "In11.Cu")
		(net "M_D_CPU0_SB_CB<0>")
	)
	(segment
		(start 269.331948 -235.990892)
		(end 268.35862 -235.990892)
		(width 0.18288)
		(layer "In11.Cu")
		(net "M_D_CPU0_SB_CB<0>")
	)
	(segment
		(start 282.175204 -234.291632)
		(end 281.32532 -235.14177)
		(width 0.18288)
		(layer "In11.Cu")
		(net "M_D_CPU0_SB_CB<0>")
	)
	(segment
		(start 336.287364 -243.607082)
		(end 336.272632 -243.598446)
		(width 0.088646)
		(layer "In11.Cu")
		(net "M_D_CPU0_SB_CB<0>")
	)
	(segment
		(start 289.65144 -234.396534)
		(end 288.514536 -234.396534)
		(width 0.18288)
		(layer "In11.Cu")
		(net "M_D_CPU0_SB_CB<0>")
	)
	(segment
		(start 309.179214 -235.152946)
		(end 308.219094 -234.192826)
		(width 0.18288)
		(layer "In11.Cu")
		(net "M_D_CPU0_SB_CB<0>")
	)
	(segment
		(start 281.32532 -235.14177)
		(end 279.364694 -235.14177)
		(width 0.18288)
		(layer "In11.Cu")
		(net "M_D_CPU0_SB_CB<0>")
	)
	(segment
		(start 314.58027 -236.611414)
		(end 313.698382 -236.611414)
		(width 0.18288)
		(layer "In11.Cu")
		(net "M_D_CPU0_SB_CB<0>")
	)
	(segment
		(start 340.046564 -243.607082)
		(end 340.031832 -243.598446)
		(width 0.088646)
		(layer "In11.Cu")
		(net "M_D_CPU0_SB_CB<0>")
	)
	(segment
		(start 303.92624 -234.472226)
		(end 303.46523 -234.011216)
		(width 0.18288)
		(layer "In11.Cu")
		(net "M_D_CPU0_SB_CB<0>")
	)
	(segment
		(start 332.32598 -242.860576)
		(end 332.077822 -242.860576)
		(width 0.088646)
		(layer "In11.Cu")
		(net "M_D_CPU0_SB_CB<0>")
	)
	(segment
		(start 303.46523 -234.011216)
		(end 299.917358 -234.011216)
		(width 0.18288)
		(layer "In11.Cu")
		(net "M_D_CPU0_SB_CB<0>")
	)
	(segment
		(start 276.863556 -236.541564)
		(end 273.179032 -236.541564)
		(width 0.18288)
		(layer "In11.Cu")
		(net "M_D_CPU0_SB_CB<0>")
	)
	(segment
		(start 265.5951 -234.700826)
		(end 264.729214 -235.566712)
		(width 0.18288)
		(layer "In11.Cu")
		(net "M_D_CPU0_SB_CB<0>")
	)
	(segment
		(start 332.998064 -242.793266)
		(end 332.983332 -242.78463)
		(width 0.088646)
		(layer "In11.Cu")
		(net "M_D_CPU0_SB_CB<0>")
	)
	(segment
		(start 335.898236 -243.598446)
		(end 335.887822 -243.604542)
		(width 0.088646)
		(layer "In11.Cu")
		(net "M_D_CPU0_SB_CB<0>")
	)
	(segment
		(start 334.958182 -243.598446)
		(end 334.94345 -243.607082)
		(width 0.088646)
		(layer "In11.Cu")
		(net "M_D_CPU0_SB_CB<0>")
	)
	(segment
		(start 269.494254 -235.828586)
		(end 269.331948 -235.990892)
		(width 0.18288)
		(layer "In11.Cu")
		(net "M_D_CPU0_SB_CB<0>")
	)
	(segment
		(start 294.037004 -235.141516)
		(end 293.893494 -235.285026)
		(width 0.18288)
		(layer "In11.Cu")
		(net "M_D_CPU0_SB_CB<0>")
	)
	(segment
		(start 278.764238 -235.742226)
		(end 277.662894 -235.742226)
		(width 0.18288)
		(layer "In11.Cu")
		(net "M_D_CPU0_SB_CB<0>")
	)
	(segment
		(start 340.986364 -243.607082)
		(end 340.971632 -243.598446)
		(width 0.088646)
		(layer "In11.Cu")
		(net "M_D_CPU0_SB_CB<0>")
	)
	(segment
		(start 267.068554 -234.700826)
		(end 265.5951 -234.700826)
		(width 0.18288)
		(layer "In11.Cu")
		(net "M_D_CPU0_SB_CB<0>")
	)
	(segment
		(start 297.339258 -234.291632)
		(end 296.961306 -234.669584)
		(width 0.18288)
		(layer "In11.Cu")
		(net "M_D_CPU0_SB_CB<0>")
	)
	(segment
		(start 343.805764 -243.607082)
		(end 343.791032 -243.598446)
		(width 0.088646)
		(layer "In11.Cu")
		(net "M_D_CPU0_SB_CB<0>")
	)
	(segment
		(start 313.698382 -236.611414)
		(end 312.002678 -234.91571)
		(width 0.18288)
		(layer "In11.Cu")
		(net "M_D_CPU0_SB_CB<0>")
	)
	(segment
		(start 315.902848 -237.159292)
		(end 314.58027 -236.611414)
		(width 0.18288)
		(layer "In11.Cu")
		(net "M_D_CPU0_SB_CB<0>")
	)
	(segment
		(start 331.657452 -242.440206)
		(end 331.613764 -242.440206)
		(width 0.088646)
		(layer "In11.Cu")
		(net "M_D_CPU0_SB_CB<0>")
	)
	(segment
		(start 310.701944 -235.152946)
		(end 309.179214 -235.152946)
		(width 0.18288)
		(layer "In11.Cu")
		(net "M_D_CPU0_SB_CB<0>")
	)
	(segment
		(start 307.076094 -234.192826)
		(end 306.796694 -234.472226)
		(width 0.18288)
		(layer "In11.Cu")
		(net "M_D_CPU0_SB_CB<0>")
	)
	(segment
		(start 288.273236 -234.155234)
		(end 284.733492 -234.155234)
		(width 0.18288)
		(layer "In11.Cu")
		(net "M_D_CPU0_SB_CB<0>")
	)
	(segment
		(start 333.932022 -242.78971)
		(end 333.923132 -242.78463)
		(width 0.088646)
		(layer "In11.Cu")
		(net "M_D_CPU0_SB_CB<0>")
	)
	(segment
		(start 344.745564 -243.607082)
		(end 344.730832 -243.598446)
		(width 0.088646)
		(layer "In11.Cu")
		(net "M_D_CPU0_SB_CB<0>")
	)
	(segment
		(start 279.364694 -235.14177)
		(end 278.764238 -235.742226)
		(width 0.18288)
		(layer "In11.Cu")
		(net "M_D_CPU0_SB_CB<0>")
	)
	(segment
		(start 299.636688 -234.291886)
		(end 298.950126 -234.291886)
		(width 0.18288)
		(layer "In11.Cu")
		(net "M_D_CPU0_SB_CB<0>")
	)
	(segment
		(start 330.53655 -241.798094)
		(end 320.54165 -241.798094)
		(width 0.18288)
		(layer "In11.Cu")
		(net "M_D_CPU0_SB_CB<0>")
	)
	(segment
		(start 292.344348 -235.285026)
		(end 292.059614 -235.000292)
		(width 0.18288)
		(layer "In11.Cu")
		(net "M_D_CPU0_SB_CB<0>")
	)
	(segment
		(start 332.077822 -242.860576)
		(end 331.657452 -242.440206)
		(width 0.088646)
		(layer "In11.Cu")
		(net "M_D_CPU0_SB_CB<0>")
	)
	(segment
		(start 320.54165 -241.798094)
		(end 315.902848 -237.159292)
		(width 0.18288)
		(layer "In11.Cu")
		(net "M_D_CPU0_SB_CB<0>")
	)
	(segment
		(start 341.921846 -243.604542)
		(end 341.911432 -243.598446)
		(width 0.088646)
		(layer "In11.Cu")
		(net "M_D_CPU0_SB_CB<0>")
	)
	(segment
		(start 310.93918 -234.91571)
		(end 310.701944 -235.152946)
		(width 0.18288)
		(layer "In11.Cu")
		(net "M_D_CPU0_SB_CB<0>")
	)
	(segment
		(start 298.950126 -234.291886)
		(end 298.949872 -234.291632)
		(width 0.18288)
		(layer "In11.Cu")
		(net "M_D_CPU0_SB_CB<0>")
	)
	(segment
		(start 290.255198 -235.000292)
		(end 289.65144 -234.396534)
		(width 0.18288)
		(layer "In11.Cu")
		(net "M_D_CPU0_SB_CB<0>")
	)
	(segment
		(start 296.245026 -234.669584)
		(end 295.773094 -235.141516)
		(width 0.18288)
		(layer "In11.Cu")
		(net "M_D_CPU0_SB_CB<0>")
	)
	(segment
		(start 284.597094 -234.291632)
		(end 282.175204 -234.291632)
		(width 0.18288)
		(layer "In11.Cu")
		(net "M_D_CPU0_SB_CB<0>")
	)
	(segment
		(start 308.219094 -234.192826)
		(end 307.076094 -234.192826)
		(width 0.18288)
		(layer "In11.Cu")
		(net "M_D_CPU0_SB_CB<0>")
	)
	(segment
		(start 272.466054 -235.828586)
		(end 269.494254 -235.828586)
		(width 0.18288)
		(layer "In11.Cu")
		(net "M_D_CPU0_SB_CB<0>")
	)
	(segment
		(start 337.227164 -243.607082)
		(end 337.212432 -243.598446)
		(width 0.088646)
		(layer "In11.Cu")
		(net "M_D_CPU0_SB_CB<0>")
	)
	(segment
		(start 346.423234 -243.922804)
		(end 346.390214 -243.890038)
		(width 0.088646)
		(layer "In11.Cu")
		(net "M_D_CPU0_SB_CB<0>")
	)
	(segment
		(start 331.178662 -242.440206)
		(end 330.53655 -241.798094)
		(width 0.18288)
		(layer "In11.Cu")
		(net "M_D_CPU0_SB_CB<0>")
	)
	(segment
		(start 342.861392 -243.604542)
		(end 342.850978 -243.598446)
		(width 0.088646)
		(layer "In11.Cu")
		(net "M_D_CPU0_SB_CB<0>")
	)
	(segment
		(start 299.917358 -234.011216)
		(end 299.636688 -234.291886)
		(width 0.18288)
		(layer "In11.Cu")
		(net "M_D_CPU0_SB_CB<0>")
	)
	(segment
		(start 295.773094 -235.141516)
		(end 294.037004 -235.141516)
		(width 0.18288)
		(layer "In11.Cu")
		(net "M_D_CPU0_SB_CB<0>")
	)
	(segment
		(start 293.893494 -235.285026)
		(end 292.344348 -235.285026)
		(width 0.18288)
		(layer "In11.Cu")
		(net "M_D_CPU0_SB_CB<0>")
	)
	(arc
		(start 345.670632 -243.598446)
		(mid 345.483434 -243.548303)
		(end 345.296236 -243.598446)
		(width 0.088646)
		(layer "In11.Cu")
		(net "M_D_CPU0_SB_CB<0>")
	)
	(arc
		(start 332.608936 -242.78463)
		(mid 332.472463 -242.841264)
		(end 332.32598 -242.860576)
		(width 0.088646)
		(layer "In11.Cu")
		(net "M_D_CPU0_SB_CB<0>")
	)
	(arc
		(start 334.94345 -243.607082)
		(mid 334.666975 -243.674402)
		(end 334.392778 -243.598446)
		(width 0.088646)
		(layer "In11.Cu")
		(net "M_D_CPU0_SB_CB<0>")
	)
	(arc
		(start 341.911432 -243.598446)
		(mid 341.724234 -243.548303)
		(end 341.537036 -243.598446)
		(width 0.088646)
		(layer "In11.Cu")
		(net "M_D_CPU0_SB_CB<0>")
	)
	(arc
		(start 344.730832 -243.598446)
		(mid 344.543634 -243.548303)
		(end 344.356436 -243.598446)
		(width 0.088646)
		(layer "In11.Cu")
		(net "M_D_CPU0_SB_CB<0>")
	)
	(arc
		(start 335.332578 -243.598446)
		(mid 335.14538 -243.548303)
		(end 334.958182 -243.598446)
		(width 0.088646)
		(layer "In11.Cu")
		(net "M_D_CPU0_SB_CB<0>")
	)
	(arc
		(start 340.031832 -243.598446)
		(mid 339.844634 -243.548303)
		(end 339.657436 -243.598446)
		(width 0.088646)
		(layer "In11.Cu")
		(net "M_D_CPU0_SB_CB<0>")
	)
	(arc
		(start 343.791032 -243.598446)
		(mid 343.603834 -243.548303)
		(end 343.416636 -243.598446)
		(width 0.088646)
		(layer "In11.Cu")
		(net "M_D_CPU0_SB_CB<0>")
	)
	(arc
		(start 337.212432 -243.598446)
		(mid 337.025234 -243.548303)
		(end 336.838036 -243.598446)
		(width 0.088646)
		(layer "In11.Cu")
		(net "M_D_CPU0_SB_CB<0>")
	)
	(arc
		(start 338.152232 -243.598446)
		(mid 337.965034 -243.548303)
		(end 337.777836 -243.598446)
		(width 0.088646)
		(layer "In11.Cu")
		(net "M_D_CPU0_SB_CB<0>")
	)
	(arc
		(start 334.110584 -243.108988)
		(mid 334.062905 -242.926088)
		(end 333.932022 -242.78971)
		(width 0.088646)
		(layer "In11.Cu")
		(net "M_D_CPU0_SB_CB<0>")
	)
	(arc
		(start 333.923132 -242.78463)
		(mid 333.735934 -242.734487)
		(end 333.548736 -242.78463)
		(width 0.088646)
		(layer "In11.Cu")
		(net "M_D_CPU0_SB_CB<0>")
	)
	(arc
		(start 345.913964 -243.672868)
		(mid 345.788052 -243.649536)
		(end 345.670632 -243.598446)
		(width 0.088646)
		(layer "In11.Cu")
		(net "M_D_CPU0_SB_CB<0>")
	)
	(arc
		(start 341.537036 -243.598446)
		(mid 341.262837 -243.674281)
		(end 340.986364 -243.607082)
		(width 0.088646)
		(layer "In11.Cu")
		(net "M_D_CPU0_SB_CB<0>")
	)
	(arc
		(start 332.983332 -242.78463)
		(mid 332.796134 -242.734487)
		(end 332.608936 -242.78463)
		(width 0.088646)
		(layer "In11.Cu")
		(net "M_D_CPU0_SB_CB<0>")
	)
	(arc
		(start 339.092032 -243.598446)
		(mid 338.904834 -243.548303)
		(end 338.717636 -243.598446)
		(width 0.088646)
		(layer "In11.Cu")
		(net "M_D_CPU0_SB_CB<0>")
	)
	(arc
		(start 343.416636 -243.598446)
		(mid 343.139823 -243.674316)
		(end 342.861392 -243.604542)
		(width 0.088646)
		(layer "In11.Cu")
		(net "M_D_CPU0_SB_CB<0>")
	)
	(arc
		(start 340.597236 -243.598446)
		(mid 340.323037 -243.674281)
		(end 340.046564 -243.607082)
		(width 0.088646)
		(layer "In11.Cu")
		(net "M_D_CPU0_SB_CB<0>")
	)
	(arc
		(start 336.838036 -243.598446)
		(mid 336.563837 -243.674281)
		(end 336.287364 -243.607082)
		(width 0.088646)
		(layer "In11.Cu")
		(net "M_D_CPU0_SB_CB<0>")
	)
	(arc
		(start 346.390214 -243.890038)
		(mid 346.171725 -243.738388)
		(end 345.913964 -243.672868)
		(width 0.088646)
		(layer "In11.Cu")
		(net "M_D_CPU0_SB_CB<0>")
	)
	(arc
		(start 344.356436 -243.598446)
		(mid 344.082237 -243.674281)
		(end 343.805764 -243.607082)
		(width 0.088646)
		(layer "In11.Cu")
		(net "M_D_CPU0_SB_CB<0>")
	)
	(arc
		(start 338.717636 -243.598446)
		(mid 338.443437 -243.674281)
		(end 338.166964 -243.607082)
		(width 0.088646)
		(layer "In11.Cu")
		(net "M_D_CPU0_SB_CB<0>")
	)
	(arc
		(start 334.392778 -243.598446)
		(mid 334.189955 -243.398215)
		(end 334.110584 -243.124482)
		(width 0.088646)
		(layer "In11.Cu")
		(net "M_D_CPU0_SB_CB<0>")
	)
	(arc
		(start 333.548736 -242.78463)
		(mid 333.274507 -242.860555)
		(end 332.998064 -242.793266)
		(width 0.088646)
		(layer "In11.Cu")
		(net "M_D_CPU0_SB_CB<0>")
	)
	(arc
		(start 340.971632 -243.598446)
		(mid 340.784434 -243.548303)
		(end 340.597236 -243.598446)
		(width 0.088646)
		(layer "In11.Cu")
		(net "M_D_CPU0_SB_CB<0>")
	)
	(arc
		(start 336.272632 -243.598446)
		(mid 336.085434 -243.548303)
		(end 335.898236 -243.598446)
		(width 0.088646)
		(layer "In11.Cu")
		(net "M_D_CPU0_SB_CB<0>")
	)
	(arc
		(start 342.476582 -243.598446)
		(mid 342.200023 -243.674189)
		(end 341.921846 -243.604542)
		(width 0.088646)
		(layer "In11.Cu")
		(net "M_D_CPU0_SB_CB<0>")
	)
	(arc
		(start 345.296236 -243.598446)
		(mid 345.022037 -243.674281)
		(end 344.745564 -243.607082)
		(width 0.088646)
		(layer "In11.Cu")
		(net "M_D_CPU0_SB_CB<0>")
	)
	(arc
		(start 342.850978 -243.598446)
		(mid 342.66378 -243.548303)
		(end 342.476582 -243.598446)
		(width 0.088646)
		(layer "In11.Cu")
		(net "M_D_CPU0_SB_CB<0>")
	)
	(arc
		(start 335.887822 -243.604542)
		(mid 335.60939 -243.674388)
		(end 335.332578 -243.598446)
		(width 0.088646)
		(layer "In11.Cu")
		(net "M_D_CPU0_SB_CB<0>")
	)
	(arc
		(start 337.777836 -243.598446)
		(mid 337.503637 -243.674281)
		(end 337.227164 -243.607082)
		(width 0.088646)
		(layer "In11.Cu")
		(net "M_D_CPU0_SB_CB<0>")
	)
	(arc
		(start 339.657436 -243.598446)
		(mid 339.374734 -243.674222)
		(end 339.092032 -243.598446)
		(width 0.088646)
		(layer "In11.Cu")
		(net "M_D_CPU0_SB_CB<0>")
	)
	(segment
		(start 258.44754 -247.03278)
		(end 258.28498 -247.19534)
		(width 0.20066)
		(layer "F.Cu")
		(net "M_D_CPU0_SB_CA<6>")
	)
	(segment
		(start 261.560056 -247.04167)
		(end 261.381494 -247.04167)
		(width 0.20066)
		(layer "F.Cu")
		(net "M_D_CPU0_SB_CA<6>")
	)
	(segment
		(start 261.381494 -247.04167)
		(end 261.050786 -247.04167)
		(width 0.101854)
		(layer "F.Cu")
		(net "M_D_CPU0_SB_CA<6>")
	)
	(segment
		(start 259.065268 -247.04167)
		(end 259.056378 -247.03278)
		(width 0.1016)
		(layer "F.Cu")
		(net "M_D_CPU0_SB_CA<6>")
	)
	(segment
		(start 342.66378 -247.178576)
		(end 342.664034 -247.178322)
		(width 0.20066)
		(layer "F.Cu")
		(net "M_D_CPU0_SB_CA<6>")
	)
	(segment
		(start 259.056378 -247.03278)
		(end 258.44754 -247.03278)
		(width 0.20066)
		(layer "F.Cu")
		(net "M_D_CPU0_SB_CA<6>")
	)
	(segment
		(start 264.729214 -247.466612)
		(end 263.624314 -247.466612)
		(width 0.20066)
		(layer "F.Cu")
		(net "M_D_CPU0_SB_CA<6>")
	)
	(segment
		(start 258.28498 -247.523508)
		(end 258.130548 -247.67794)
		(width 0.20066)
		(layer "F.Cu")
		(net "M_D_CPU0_SB_CA<6>")
	)
	(segment
		(start 342.66378 -247.714262)
		(end 342.66378 -247.178576)
		(width 0.20066)
		(layer "F.Cu")
		(net "M_D_CPU0_SB_CA<6>")
	)
	(segment
		(start 258.130548 -247.67794)
		(end 257.626104 -247.67794)
		(width 0.20066)
		(layer "F.Cu")
		(net "M_D_CPU0_SB_CA<6>")
	)
	(segment
		(start 257.626104 -247.67794)
		(end 257.414776 -247.466612)
		(width 0.20066)
		(layer "F.Cu")
		(net "M_D_CPU0_SB_CA<6>")
	)
	(segment
		(start 261.984998 -247.466612)
		(end 261.560056 -247.04167)
		(width 0.20066)
		(layer "F.Cu")
		(net "M_D_CPU0_SB_CA<6>")
	)
	(segment
		(start 263.624314 -247.466612)
		(end 261.984998 -247.466612)
		(width 0.20066)
		(layer "F.Cu")
		(net "M_D_CPU0_SB_CA<6>")
	)
	(segment
		(start 257.414776 -247.466612)
		(end 256.080514 -247.466612)
		(width 0.20066)
		(layer "F.Cu")
		(net "M_D_CPU0_SB_CA<6>")
	)
	(segment
		(start 258.28498 -247.19534)
		(end 258.28498 -247.523508)
		(width 0.20066)
		(layer "F.Cu")
		(net "M_D_CPU0_SB_CA<6>")
	)
	(segment
		(start 261.050786 -247.04167)
		(end 259.065268 -247.04167)
		(width 0.1016)
		(layer "F.Cu")
		(net "M_D_CPU0_SB_CA<6>")
	)
	(segment
		(start 278.475694 -247.223026)
		(end 277.548594 -247.223026)
		(width 0.18288)
		(layer "In11.Cu")
		(net "M_D_CPU0_SB_CA<6>")
	)
	(segment
		(start 267.684504 -247.371616)
		(end 267.491464 -247.178576)
		(width 0.18288)
		(layer "In11.Cu")
		(net "M_D_CPU0_SB_CA<6>")
	)
	(segment
		(start 266.089384 -246.372126)
		(end 265.896344 -246.179086)
		(width 0.18288)
		(layer "In11.Cu")
		(net "M_D_CPU0_SB_CA<6>")
	)
	(segment
		(start 338.162392 -247.496584)
		(end 338.151978 -247.50268)
		(width 0.088646)
		(layer "In11.Cu")
		(net "M_D_CPU0_SB_CA<6>")
	)
	(segment
		(start 314.383928 -244.632226)
		(end 311.094374 -244.632226)
		(width 0.18288)
		(layer "In11.Cu")
		(net "M_D_CPU0_SB_CA<6>")
	)
	(segment
		(start 300.963076 -247.156986)
		(end 300.770036 -247.350026)
		(width 0.18288)
		(layer "In11.Cu")
		(net "M_D_CPU0_SB_CA<6>")
	)
	(segment
		(start 267.990828 -247.371616)
		(end 267.684504 -247.371616)
		(width 0.18288)
		(layer "In11.Cu")
		(net "M_D_CPU0_SB_CA<6>")
	)
	(segment
		(start 341.926164 -247.494044)
		(end 341.911432 -247.50268)
		(width 0.088646)
		(layer "In11.Cu")
		(net "M_D_CPU0_SB_CA<6>")
	)
	(segment
		(start 331.919072 -247.211596)
		(end 331.821028 -247.113552)
		(width 0.088646)
		(layer "In11.Cu")
		(net "M_D_CPU0_SB_CA<6>")
	)
	(segment
		(start 265.252962 -246.44985)
		(end 265.252962 -246.942864)
		(width 0.18288)
		(layer "In11.Cu")
		(net "M_D_CPU0_SB_CA<6>")
	)
	(segment
		(start 311.094374 -244.632226)
		(end 310.223154 -245.503446)
		(width 0.18288)
		(layer "In11.Cu")
		(net "M_D_CPU0_SB_CA<6>")
	)
	(segment
		(start 302.541686 -247.350026)
		(end 301.857156 -247.350026)
		(width 0.18288)
		(layer "In11.Cu")
		(net "M_D_CPU0_SB_CA<6>")
	)
	(segment
		(start 272.798794 -246.867426)
		(end 272.544794 -247.121426)
		(width 0.18288)
		(layer "In11.Cu")
		(net "M_D_CPU0_SB_CA<6>")
	)
	(segment
		(start 266.790424 -246.83593)
		(end 266.597384 -247.02897)
		(width 0.18288)
		(layer "In11.Cu")
		(net "M_D_CPU0_SB_CA<6>")
	)
	(segment
		(start 340.986364 -247.494044)
		(end 340.971632 -247.50268)
		(width 0.088646)
		(layer "In11.Cu")
		(net "M_D_CPU0_SB_CA<6>")
	)
	(segment
		(start 277.192994 -246.867426)
		(end 272.798794 -246.867426)
		(width 0.18288)
		(layer "In11.Cu")
		(net "M_D_CPU0_SB_CA<6>")
	)
	(segment
		(start 299.707554 -247.038368)
		(end 293.683182 -247.038368)
		(width 0.18288)
		(layer "In11.Cu")
		(net "M_D_CPU0_SB_CA<6>")
	)
	(segment
		(start 266.597384 -247.02897)
		(end 266.282424 -247.02897)
		(width 0.18288)
		(layer "In11.Cu")
		(net "M_D_CPU0_SB_CA<6>")
	)
	(segment
		(start 310.223154 -245.503446)
		(end 307.746654 -245.503446)
		(width 0.18288)
		(layer "In11.Cu")
		(net "M_D_CPU0_SB_CA<6>")
	)
	(segment
		(start 328.93635 -247.113552)
		(end 328.42327 -246.600472)
		(width 0.18288)
		(layer "In11.Cu")
		(net "M_D_CPU0_SB_CA<6>")
	)
	(segment
		(start 301.156116 -246.595392)
		(end 300.963076 -246.788432)
		(width 0.18288)
		(layer "In11.Cu")
		(net "M_D_CPU0_SB_CA<6>")
	)
	(segment
		(start 272.544794 -247.121426)
		(end 272.112994 -247.121426)
		(width 0.18288)
		(layer "In11.Cu")
		(net "M_D_CPU0_SB_CA<6>")
	)
	(segment
		(start 265.5824 -246.179086)
		(end 265.570716 -246.19077)
		(width 0.18288)
		(layer "In11.Cu")
		(net "M_D_CPU0_SB_CA<6>")
	)
	(segment
		(start 288.694876 -246.833644)
		(end 288.413444 -247.115076)
		(width 0.18288)
		(layer "In11.Cu")
		(net "M_D_CPU0_SB_CA<6>")
	)
	(segment
		(start 342.191848 -247.419622)
		(end 342.103964 -247.433846)
		(width 0.088646)
		(layer "In11.Cu")
		(net "M_D_CPU0_SB_CA<6>")
	)
	(segment
		(start 307.746654 -245.503446)
		(end 306.817014 -246.433086)
		(width 0.18288)
		(layer "In11.Cu")
		(net "M_D_CPU0_SB_CA<6>")
	)
	(segment
		(start 301.471076 -246.595392)
		(end 301.156116 -246.595392)
		(width 0.18288)
		(layer "In11.Cu")
		(net "M_D_CPU0_SB_CA<6>")
	)
	(segment
		(start 266.790424 -246.372126)
		(end 266.790424 -246.83593)
		(width 0.18288)
		(layer "In11.Cu")
		(net "M_D_CPU0_SB_CA<6>")
	)
	(segment
		(start 266.089384 -246.83593)
		(end 266.089384 -246.372126)
		(width 0.18288)
		(layer "In11.Cu")
		(net "M_D_CPU0_SB_CA<6>")
	)
	(segment
		(start 332.164436 -247.553226)
		(end 331.919072 -247.307862)
		(width 0.088646)
		(layer "In11.Cu")
		(net "M_D_CPU0_SB_CA<6>")
	)
	(segment
		(start 332.326234 -247.553226)
		(end 332.164436 -247.553226)
		(width 0.088646)
		(layer "In11.Cu")
		(net "M_D_CPU0_SB_CA<6>")
	)
	(segment
		(start 266.983464 -246.179086)
		(end 266.790424 -246.372126)
		(width 0.18288)
		(layer "In11.Cu")
		(net "M_D_CPU0_SB_CA<6>")
	)
	(segment
		(start 293.683182 -247.038368)
		(end 293.562532 -247.159018)
		(width 0.18288)
		(layer "In11.Cu")
		(net "M_D_CPU0_SB_CA<6>")
	)
	(segment
		(start 293.562532 -247.159018)
		(end 292.13175 -247.159018)
		(width 0.18288)
		(layer "In11.Cu")
		(net "M_D_CPU0_SB_CA<6>")
	)
	(segment
		(start 301.664116 -247.156986)
		(end 301.664116 -246.788432)
		(width 0.18288)
		(layer "In11.Cu")
		(net "M_D_CPU0_SB_CA<6>")
	)
	(segment
		(start 301.857156 -247.350026)
		(end 301.664116 -247.156986)
		(width 0.18288)
		(layer "In11.Cu")
		(net "M_D_CPU0_SB_CA<6>")
	)
	(segment
		(start 265.896344 -246.179086)
		(end 265.5824 -246.179086)
		(width 0.18288)
		(layer "In11.Cu")
		(net "M_D_CPU0_SB_CA<6>")
	)
	(segment
		(start 300.963076 -246.788432)
		(end 300.963076 -247.156986)
		(width 0.18288)
		(layer "In11.Cu")
		(net "M_D_CPU0_SB_CA<6>")
	)
	(segment
		(start 282.231592 -246.837708)
		(end 281.295602 -246.837708)
		(width 0.18288)
		(layer "In11.Cu")
		(net "M_D_CPU0_SB_CA<6>")
	)
	(segment
		(start 337.777582 -247.50268)
		(end 337.767168 -247.496584)
		(width 0.088646)
		(layer "In11.Cu")
		(net "M_D_CPU0_SB_CA<6>")
	)
	(segment
		(start 291.806376 -246.833644)
		(end 288.694876 -246.833644)
		(width 0.18288)
		(layer "In11.Cu")
		(net "M_D_CPU0_SB_CA<6>")
	)
	(segment
		(start 336.287364 -247.494044)
		(end 336.272632 -247.50268)
		(width 0.088646)
		(layer "In11.Cu")
		(net "M_D_CPU0_SB_CA<6>")
	)
	(segment
		(start 265.512042 -246.19077)
		(end 265.252962 -246.44985)
		(width 0.18288)
		(layer "In11.Cu")
		(net "M_D_CPU0_SB_CA<6>")
	)
	(segment
		(start 316.352174 -246.600472)
		(end 314.383928 -244.632226)
		(width 0.18288)
		(layer "In11.Cu")
		(net "M_D_CPU0_SB_CA<6>")
	)
	(segment
		(start 301.664116 -246.788432)
		(end 301.471076 -246.595392)
		(width 0.18288)
		(layer "In11.Cu")
		(net "M_D_CPU0_SB_CA<6>")
	)
	(segment
		(start 340.041992 -247.496584)
		(end 340.031578 -247.50268)
		(width 0.088646)
		(layer "In11.Cu")
		(net "M_D_CPU0_SB_CA<6>")
	)
	(segment
		(start 303.458626 -246.433086)
		(end 302.541686 -247.350026)
		(width 0.18288)
		(layer "In11.Cu")
		(net "M_D_CPU0_SB_CA<6>")
	)
	(segment
		(start 267.298424 -246.179086)
		(end 266.983464 -246.179086)
		(width 0.18288)
		(layer "In11.Cu")
		(net "M_D_CPU0_SB_CA<6>")
	)
	(segment
		(start 281.295602 -246.837708)
		(end 281.092148 -247.041162)
		(width 0.18288)
		(layer "In11.Cu")
		(net "M_D_CPU0_SB_CA<6>")
	)
	(segment
		(start 331.613764 -247.113552)
		(end 328.93635 -247.113552)
		(width 0.18288)
		(layer "In11.Cu")
		(net "M_D_CPU0_SB_CA<6>")
	)
	(segment
		(start 268.192504 -247.16994)
		(end 267.990828 -247.371616)
		(width 0.18288)
		(layer "In11.Cu")
		(net "M_D_CPU0_SB_CA<6>")
	)
	(segment
		(start 288.413444 -247.115076)
		(end 284.949646 -247.115076)
		(width 0.18288)
		(layer "In11.Cu")
		(net "M_D_CPU0_SB_CA<6>")
	)
	(segment
		(start 328.42327 -246.600472)
		(end 316.352174 -246.600472)
		(width 0.18288)
		(layer "In11.Cu")
		(net "M_D_CPU0_SB_CA<6>")
	)
	(segment
		(start 265.252962 -246.942864)
		(end 264.729214 -247.466612)
		(width 0.18288)
		(layer "In11.Cu")
		(net "M_D_CPU0_SB_CA<6>")
	)
	(segment
		(start 278.657558 -247.041162)
		(end 278.475694 -247.223026)
		(width 0.18288)
		(layer "In11.Cu")
		(net "M_D_CPU0_SB_CA<6>")
	)
	(segment
		(start 267.491464 -247.178576)
		(end 267.491464 -246.372126)
		(width 0.18288)
		(layer "In11.Cu")
		(net "M_D_CPU0_SB_CA<6>")
	)
	(segment
		(start 265.570716 -246.19077)
		(end 265.512042 -246.19077)
		(width 0.18288)
		(layer "In11.Cu")
		(net "M_D_CPU0_SB_CA<6>")
	)
	(segment
		(start 300.770036 -247.350026)
		(end 300.019212 -247.350026)
		(width 0.18288)
		(layer "In11.Cu")
		(net "M_D_CPU0_SB_CA<6>")
	)
	(segment
		(start 292.13175 -247.159018)
		(end 291.806376 -246.833644)
		(width 0.18288)
		(layer "In11.Cu")
		(net "M_D_CPU0_SB_CA<6>")
	)
	(segment
		(start 272.112994 -247.121426)
		(end 271.180814 -246.189246)
		(width 0.18288)
		(layer "In11.Cu")
		(net "M_D_CPU0_SB_CA<6>")
	)
	(segment
		(start 339.657182 -247.50268)
		(end 339.646768 -247.496584)
		(width 0.088646)
		(layer "In11.Cu")
		(net "M_D_CPU0_SB_CA<6>")
	)
	(segment
		(start 282.435046 -247.041162)
		(end 282.231592 -246.837708)
		(width 0.18288)
		(layer "In11.Cu")
		(net "M_D_CPU0_SB_CA<6>")
	)
	(segment
		(start 281.092148 -247.041162)
		(end 278.657558 -247.041162)
		(width 0.18288)
		(layer "In11.Cu")
		(net "M_D_CPU0_SB_CA<6>")
	)
	(segment
		(start 271.180814 -246.189246)
		(end 268.385544 -246.189246)
		(width 0.18288)
		(layer "In11.Cu")
		(net "M_D_CPU0_SB_CA<6>")
	)
	(segment
		(start 268.385544 -246.189246)
		(end 268.192504 -246.382286)
		(width 0.18288)
		(layer "In11.Cu")
		(net "M_D_CPU0_SB_CA<6>")
	)
	(segment
		(start 267.491464 -246.372126)
		(end 267.298424 -246.179086)
		(width 0.18288)
		(layer "In11.Cu")
		(net "M_D_CPU0_SB_CA<6>")
	)
	(segment
		(start 268.192504 -246.382286)
		(end 268.192504 -247.16994)
		(width 0.18288)
		(layer "In11.Cu")
		(net "M_D_CPU0_SB_CA<6>")
	)
	(segment
		(start 277.548594 -247.223026)
		(end 277.192994 -246.867426)
		(width 0.18288)
		(layer "In11.Cu")
		(net "M_D_CPU0_SB_CA<6>")
	)
	(segment
		(start 306.817014 -246.433086)
		(end 303.458626 -246.433086)
		(width 0.18288)
		(layer "In11.Cu")
		(net "M_D_CPU0_SB_CA<6>")
	)
	(segment
		(start 266.282424 -247.02897)
		(end 266.089384 -246.83593)
		(width 0.18288)
		(layer "In11.Cu")
		(net "M_D_CPU0_SB_CA<6>")
	)
	(segment
		(start 331.821028 -247.113552)
		(end 331.613764 -247.113552)
		(width 0.088646)
		(layer "In11.Cu")
		(net "M_D_CPU0_SB_CA<6>")
	)
	(segment
		(start 284.875732 -247.041162)
		(end 282.435046 -247.041162)
		(width 0.18288)
		(layer "In11.Cu")
		(net "M_D_CPU0_SB_CA<6>")
	)
	(segment
		(start 331.919072 -247.307862)
		(end 331.919072 -247.211596)
		(width 0.088646)
		(layer "In11.Cu")
		(net "M_D_CPU0_SB_CA<6>")
	)
	(segment
		(start 300.019212 -247.350026)
		(end 299.707554 -247.038368)
		(width 0.18288)
		(layer "In11.Cu")
		(net "M_D_CPU0_SB_CA<6>")
	)
	(segment
		(start 284.949646 -247.115076)
		(end 284.875732 -247.041162)
		(width 0.18288)
		(layer "In11.Cu")
		(net "M_D_CPU0_SB_CA<6>")
	)
	(arc
		(start 340.971632 -247.50268)
		(mid 340.784434 -247.552823)
		(end 340.597236 -247.50268)
		(width 0.088646)
		(layer "In11.Cu")
		(net "M_D_CPU0_SB_CA<6>")
	)
	(arc
		(start 342.103964 -247.433846)
		(mid 342.012548 -247.456514)
		(end 341.926164 -247.494044)
		(width 0.088646)
		(layer "In11.Cu")
		(net "M_D_CPU0_SB_CA<6>")
	)
	(arc
		(start 333.453232 -247.50268)
		(mid 333.266034 -247.552823)
		(end 333.078836 -247.50268)
		(width 0.088646)
		(layer "In11.Cu")
		(net "M_D_CPU0_SB_CA<6>")
	)
	(arc
		(start 335.898236 -247.50268)
		(mid 335.615534 -247.426904)
		(end 335.332832 -247.50268)
		(width 0.088646)
		(layer "In11.Cu")
		(net "M_D_CPU0_SB_CA<6>")
	)
	(arc
		(start 334.958436 -247.50268)
		(mid 334.675734 -247.426904)
		(end 334.393032 -247.50268)
		(width 0.088646)
		(layer "In11.Cu")
		(net "M_D_CPU0_SB_CA<6>")
	)
	(arc
		(start 334.393032 -247.50268)
		(mid 334.205834 -247.552823)
		(end 334.018636 -247.50268)
		(width 0.088646)
		(layer "In11.Cu")
		(net "M_D_CPU0_SB_CA<6>")
	)
	(arc
		(start 342.664034 -247.178322)
		(mid 342.446962 -247.336189)
		(end 342.191848 -247.419622)
		(width 0.088646)
		(layer "In11.Cu")
		(net "M_D_CPU0_SB_CA<6>")
	)
	(arc
		(start 333.078836 -247.50268)
		(mid 332.796134 -247.426904)
		(end 332.513432 -247.50268)
		(width 0.088646)
		(layer "In11.Cu")
		(net "M_D_CPU0_SB_CA<6>")
	)
	(arc
		(start 340.597236 -247.50268)
		(mid 340.320423 -247.42681)
		(end 340.041992 -247.496584)
		(width 0.088646)
		(layer "In11.Cu")
		(net "M_D_CPU0_SB_CA<6>")
	)
	(arc
		(start 339.646768 -247.496584)
		(mid 339.36859 -247.426861)
		(end 339.092032 -247.50268)
		(width 0.088646)
		(layer "In11.Cu")
		(net "M_D_CPU0_SB_CA<6>")
	)
	(arc
		(start 340.031578 -247.50268)
		(mid 339.84438 -247.552823)
		(end 339.657182 -247.50268)
		(width 0.088646)
		(layer "In11.Cu")
		(net "M_D_CPU0_SB_CA<6>")
	)
	(arc
		(start 336.838036 -247.50268)
		(mid 336.563837 -247.426845)
		(end 336.287364 -247.494044)
		(width 0.088646)
		(layer "In11.Cu")
		(net "M_D_CPU0_SB_CA<6>")
	)
	(arc
		(start 337.212432 -247.50268)
		(mid 337.025234 -247.552823)
		(end 336.838036 -247.50268)
		(width 0.088646)
		(layer "In11.Cu")
		(net "M_D_CPU0_SB_CA<6>")
	)
	(arc
		(start 338.717636 -247.50268)
		(mid 338.440823 -247.42681)
		(end 338.162392 -247.496584)
		(width 0.088646)
		(layer "In11.Cu")
		(net "M_D_CPU0_SB_CA<6>")
	)
	(arc
		(start 337.767168 -247.496584)
		(mid 337.48899 -247.426861)
		(end 337.212432 -247.50268)
		(width 0.088646)
		(layer "In11.Cu")
		(net "M_D_CPU0_SB_CA<6>")
	)
	(arc
		(start 341.911432 -247.50268)
		(mid 341.724234 -247.552823)
		(end 341.537036 -247.50268)
		(width 0.088646)
		(layer "In11.Cu")
		(net "M_D_CPU0_SB_CA<6>")
	)
	(arc
		(start 336.272632 -247.50268)
		(mid 336.085434 -247.552823)
		(end 335.898236 -247.50268)
		(width 0.088646)
		(layer "In11.Cu")
		(net "M_D_CPU0_SB_CA<6>")
	)
	(arc
		(start 338.151978 -247.50268)
		(mid 337.96478 -247.552823)
		(end 337.777582 -247.50268)
		(width 0.088646)
		(layer "In11.Cu")
		(net "M_D_CPU0_SB_CA<6>")
	)
	(arc
		(start 334.018636 -247.50268)
		(mid 333.735934 -247.426904)
		(end 333.453232 -247.50268)
		(width 0.088646)
		(layer "In11.Cu")
		(net "M_D_CPU0_SB_CA<6>")
	)
	(arc
		(start 341.537036 -247.50268)
		(mid 341.262837 -247.426845)
		(end 340.986364 -247.494044)
		(width 0.088646)
		(layer "In11.Cu")
		(net "M_D_CPU0_SB_CA<6>")
	)
	(arc
		(start 339.092032 -247.50268)
		(mid 338.904834 -247.552823)
		(end 338.717636 -247.50268)
		(width 0.088646)
		(layer "In11.Cu")
		(net "M_D_CPU0_SB_CA<6>")
	)
	(arc
		(start 335.332832 -247.50268)
		(mid 335.145634 -247.552823)
		(end 334.958436 -247.50268)
		(width 0.088646)
		(layer "In11.Cu")
		(net "M_D_CPU0_SB_CA<6>")
	)
	(arc
		(start 332.513432 -247.50268)
		(mid 332.42316 -247.540279)
		(end 332.326234 -247.553226)
		(width 0.088646)
		(layer "In11.Cu")
		(net "M_D_CPU0_SB_CA<6>")
	)
	(segment
		(start 266.90828 -248.31675)
		(end 266.700762 -248.524268)
		(width 0.20066)
		(layer "F.Cu")
		(net "M_D_CPU0_SB_CA<5>")
	)
	(segment
		(start 345.01328 -248.527824)
		(end 345.01328 -247.992138)
		(width 0.20066)
		(layer "F.Cu")
		(net "M_D_CPU0_SB_CA<5>")
	)
	(segment
		(start 265.369548 -248.741692)
		(end 264.825226 -248.741692)
		(width 0.20066)
		(layer "F.Cu")
		(net "M_D_CPU0_SB_CA<5>")
	)
	(segment
		(start 266.042394 -248.312432)
		(end 265.64717 -248.312432)
		(width 0.20066)
		(layer "F.Cu")
		(net "M_D_CPU0_SB_CA<5>")
	)
	(segment
		(start 264.825226 -248.741692)
		(end 262.752332 -248.741692)
		(width 0.1016)
		(layer "F.Cu")
		(net "M_D_CPU0_SB_CA<5>")
	)
	(segment
		(start 262.50011 -248.755916)
		(end 262.146288 -248.755916)
		(width 0.20066)
		(layer "F.Cu")
		(net "M_D_CPU0_SB_CA<5>")
	)
	(segment
		(start 262.003794 -248.613422)
		(end 262.003794 -248.442734)
		(width 0.20066)
		(layer "F.Cu")
		(net "M_D_CPU0_SB_CA<5>")
	)
	(segment
		(start 262.752332 -248.741692)
		(end 262.514334 -248.741692)
		(width 0.101854)
		(layer "F.Cu")
		(net "M_D_CPU0_SB_CA<5>")
	)
	(segment
		(start 265.518646 -248.440956)
		(end 265.518646 -248.592594)
		(width 0.20066)
		(layer "F.Cu")
		(net "M_D_CPU0_SB_CA<5>")
	)
	(segment
		(start 261.87781 -248.31675)
		(end 260.180582 -248.31675)
		(width 0.20066)
		(layer "F.Cu")
		(net "M_D_CPU0_SB_CA<5>")
	)
	(segment
		(start 268.829282 -248.31675)
		(end 267.724382 -248.31675)
		(width 0.20066)
		(layer "F.Cu")
		(net "M_D_CPU0_SB_CA<5>")
	)
	(segment
		(start 265.518646 -248.592594)
		(end 265.369548 -248.741692)
		(width 0.20066)
		(layer "F.Cu")
		(net "M_D_CPU0_SB_CA<5>")
	)
	(segment
		(start 262.146288 -248.755916)
		(end 262.003794 -248.613422)
		(width 0.20066)
		(layer "F.Cu")
		(net "M_D_CPU0_SB_CA<5>")
	)
	(segment
		(start 266.700762 -248.524268)
		(end 266.25423 -248.524268)
		(width 0.20066)
		(layer "F.Cu")
		(net "M_D_CPU0_SB_CA<5>")
	)
	(segment
		(start 265.64717 -248.312432)
		(end 265.518646 -248.440956)
		(width 0.20066)
		(layer "F.Cu")
		(net "M_D_CPU0_SB_CA<5>")
	)
	(segment
		(start 266.25423 -248.524268)
		(end 266.042394 -248.312432)
		(width 0.20066)
		(layer "F.Cu")
		(net "M_D_CPU0_SB_CA<5>")
	)
	(segment
		(start 267.724382 -248.31675)
		(end 266.90828 -248.31675)
		(width 0.20066)
		(layer "F.Cu")
		(net "M_D_CPU0_SB_CA<5>")
	)
	(segment
		(start 262.514334 -248.741692)
		(end 262.50011 -248.755916)
		(width 0.101854)
		(layer "F.Cu")
		(net "M_D_CPU0_SB_CA<5>")
	)
	(segment
		(start 262.003794 -248.442734)
		(end 261.87781 -248.31675)
		(width 0.20066)
		(layer "F.Cu")
		(net "M_D_CPU0_SB_CA<5>")
	)
	(segment
		(start 345.013534 -248.528078)
		(end 345.01328 -248.527824)
		(width 0.20066)
		(layer "F.Cu")
		(net "M_D_CPU0_SB_CA<5>")
	)
	(segment
		(start 278.904192 -248.483882)
		(end 278.711152 -248.290842)
		(width 0.18288)
		(layer "In11.Cu")
		(net "M_D_CPU0_SB_CA<5>")
	)
	(segment
		(start 301.107856 -248.714006)
		(end 300.914816 -248.907046)
		(width 0.18288)
		(layer "In11.Cu")
		(net "M_D_CPU0_SB_CA<5>")
	)
	(segment
		(start 345.01328 -247.992138)
		(end 345.169744 -247.72112)
		(width 0.088646)
		(layer "In11.Cu")
		(net "M_D_CPU0_SB_CA<5>")
	)
	(segment
		(start 282.979114 -248.121932)
		(end 282.664154 -248.121932)
		(width 0.18288)
		(layer "In11.Cu")
		(net "M_D_CPU0_SB_CA<5>")
	)
	(segment
		(start 308.674262 -247.776746)
		(end 307.614574 -247.776746)
		(width 0.18288)
		(layer "In11.Cu")
		(net "M_D_CPU0_SB_CA<5>")
	)
	(segment
		(start 328.712576 -247.86717)
		(end 328.154792 -247.309386)
		(width 0.18288)
		(layer "In11.Cu")
		(net "M_D_CPU0_SB_CA<5>")
	)
	(segment
		(start 321.991482 -248.080022)
		(end 316.079378 -248.080022)
		(width 0.18288)
		(layer "In11.Cu")
		(net "M_D_CPU0_SB_CA<5>")
	)
	(segment
		(start 343.886536 -247.66778)
		(end 343.876122 -247.673876)
		(width 0.088646)
		(layer "In11.Cu")
		(net "M_D_CPU0_SB_CA<5>")
	)
	(segment
		(start 337.307936 -248.316496)
		(end 337.297522 -248.3104)
		(width 0.088646)
		(layer "In11.Cu")
		(net "M_D_CPU0_SB_CA<5>")
	)
	(segment
		(start 301.615856 -248.403872)
		(end 301.300896 -248.403872)
		(width 0.18288)
		(layer "In11.Cu")
		(net "M_D_CPU0_SB_CA<5>")
	)
	(segment
		(start 305.572922 -247.501664)
		(end 305.257962 -247.501664)
		(width 0.18288)
		(layer "In11.Cu")
		(net "M_D_CPU0_SB_CA<5>")
	)
	(segment
		(start 307.614574 -247.776746)
		(end 307.379624 -248.011696)
		(width 0.18288)
		(layer "In11.Cu")
		(net "M_D_CPU0_SB_CA<5>")
	)
	(segment
		(start 293.489126 -248.414794)
		(end 293.489126 -248.548144)
		(width 0.18288)
		(layer "In11.Cu")
		(net "M_D_CPU0_SB_CA<5>")
	)
	(segment
		(start 293.489126 -248.548144)
		(end 293.296086 -248.741184)
		(width 0.18288)
		(layer "In11.Cu")
		(net "M_D_CPU0_SB_CA<5>")
	)
	(segment
		(start 278.711152 -248.290842)
		(end 278.396192 -248.290842)
		(width 0.18288)
		(layer "In11.Cu")
		(net "M_D_CPU0_SB_CA<5>")
	)
	(segment
		(start 270.67764 -248.975626)
		(end 269.488158 -248.975626)
		(width 0.18288)
		(layer "In11.Cu")
		(net "M_D_CPU0_SB_CA<5>")
	)
	(segment
		(start 269.488158 -248.975626)
		(end 268.829282 -248.31675)
		(width 0.18288)
		(layer "In11.Cu")
		(net "M_D_CPU0_SB_CA<5>")
	)
	(segment
		(start 294.190166 -248.548144)
		(end 294.190166 -248.414794)
		(width 0.18288)
		(layer "In11.Cu")
		(net "M_D_CPU0_SB_CA<5>")
	)
	(segment
		(start 280.944828 -249.037094)
		(end 280.539698 -249.037094)
		(width 0.18288)
		(layer "In11.Cu")
		(net "M_D_CPU0_SB_CA<5>")
	)
	(segment
		(start 302.623474 -248.907046)
		(end 302.001936 -248.907046)
		(width 0.18288)
		(layer "In11.Cu")
		(net "M_D_CPU0_SB_CA<5>")
	)
	(segment
		(start 345.169744 -247.72112)
		(end 345.148662 -247.643142)
		(width 0.088646)
		(layer "In11.Cu")
		(net "M_D_CPU0_SB_CA<5>")
	)
	(segment
		(start 336.367882 -248.316496)
		(end 336.357468 -248.3104)
		(width 0.088646)
		(layer "In11.Cu")
		(net "M_D_CPU0_SB_CA<5>")
	)
	(segment
		(start 278.203152 -248.706386)
		(end 278.010112 -248.899426)
		(width 0.18288)
		(layer "In11.Cu")
		(net "M_D_CPU0_SB_CA<5>")
	)
	(segment
		(start 289.883088 -248.849388)
		(end 289.690048 -248.656348)
		(width 0.18288)
		(layer "In11.Cu")
		(net "M_D_CPU0_SB_CA<5>")
	)
	(segment
		(start 293.04996 -248.741184)
		(end 292.917118 -248.874026)
		(width 0.18288)
		(layer "In11.Cu")
		(net "M_D_CPU0_SB_CA<5>")
	)
	(segment
		(start 314.460128 -246.460772)
		(end 311.053988 -246.460772)
		(width 0.18288)
		(layer "In11.Cu")
		(net "M_D_CPU0_SB_CA<5>")
	)
	(segment
		(start 293.997126 -248.221754)
		(end 293.682166 -248.221754)
		(width 0.18288)
		(layer "In11.Cu")
		(net "M_D_CPU0_SB_CA<5>")
	)
	(segment
		(start 294.190166 -248.414794)
		(end 293.997126 -248.221754)
		(width 0.18288)
		(layer "In11.Cu")
		(net "M_D_CPU0_SB_CA<5>")
	)
	(segment
		(start 296.122852 -248.518426)
		(end 295.900094 -248.741184)
		(width 0.18288)
		(layer "In11.Cu")
		(net "M_D_CPU0_SB_CA<5>")
	)
	(segment
		(start 305.959002 -248.011696)
		(end 305.765962 -247.818656)
		(width 0.18288)
		(layer "In11.Cu")
		(net "M_D_CPU0_SB_CA<5>")
	)
	(segment
		(start 273.330162 -248.594626)
		(end 272.949162 -248.975626)
		(width 0.18288)
		(layer "In11.Cu")
		(net "M_D_CPU0_SB_CA<5>")
	)
	(segment
		(start 293.682166 -248.221754)
		(end 293.489126 -248.414794)
		(width 0.18288)
		(layer "In11.Cu")
		(net "M_D_CPU0_SB_CA<5>")
	)
	(segment
		(start 280.539698 -249.037094)
		(end 280.243788 -248.741184)
		(width 0.18288)
		(layer "In11.Cu")
		(net "M_D_CPU0_SB_CA<5>")
	)
	(segment
		(start 292.197536 -248.874026)
		(end 291.979858 -248.656348)
		(width 0.18288)
		(layer "In11.Cu")
		(net "M_D_CPU0_SB_CA<5>")
	)
	(segment
		(start 332.530958 -248.257314)
		(end 332.292452 -248.018808)
		(width 0.088646)
		(layer "In11.Cu")
		(net "M_D_CPU0_SB_CA<5>")
	)
	(segment
		(start 300.091094 -248.74093)
		(end 297.544998 -248.74093)
		(width 0.18288)
		(layer "In11.Cu")
		(net "M_D_CPU0_SB_CA<5>")
	)
	(segment
		(start 290.777168 -248.656348)
		(end 290.584128 -248.849388)
		(width 0.18288)
		(layer "In11.Cu")
		(net "M_D_CPU0_SB_CA<5>")
	)
	(segment
		(start 271.57172 -248.462546)
		(end 271.37868 -248.269506)
		(width 0.18288)
		(layer "In11.Cu")
		(net "M_D_CPU0_SB_CA<5>")
	)
	(segment
		(start 275.458428 -249.299476)
		(end 274.989036 -249.299476)
		(width 0.18288)
		(layer "In11.Cu")
		(net "M_D_CPU0_SB_CA<5>")
	)
	(segment
		(start 280.243788 -248.741184)
		(end 279.510236 -248.741184)
		(width 0.18288)
		(layer "In11.Cu")
		(net "M_D_CPU0_SB_CA<5>")
	)
	(segment
		(start 311.053988 -246.460772)
		(end 310.248554 -247.266206)
		(width 0.18288)
		(layer "In11.Cu")
		(net "M_D_CPU0_SB_CA<5>")
	)
	(segment
		(start 294.383206 -248.741184)
		(end 294.190166 -248.548144)
		(width 0.18288)
		(layer "In11.Cu")
		(net "M_D_CPU0_SB_CA<5>")
	)
	(segment
		(start 301.300896 -248.403872)
		(end 301.107856 -248.596912)
		(width 0.18288)
		(layer "In11.Cu")
		(net "M_D_CPU0_SB_CA<5>")
	)
	(segment
		(start 281.274266 -248.707656)
		(end 280.944828 -249.037094)
		(width 0.18288)
		(layer "In11.Cu")
		(net "M_D_CPU0_SB_CA<5>")
	)
	(segment
		(start 278.396192 -248.290842)
		(end 278.203152 -248.483882)
		(width 0.18288)
		(layer "In11.Cu")
		(net "M_D_CPU0_SB_CA<5>")
	)
	(segment
		(start 282.664154 -248.121932)
		(end 282.471114 -248.314972)
		(width 0.18288)
		(layer "In11.Cu")
		(net "M_D_CPU0_SB_CA<5>")
	)
	(segment
		(start 342.717374 -247.843548)
		(end 342.67648 -247.884442)
		(width 0.088646)
		(layer "In11.Cu")
		(net "M_D_CPU0_SB_CA<5>")
	)
	(segment
		(start 344.271346 -247.673876)
		(end 344.260932 -247.66778)
		(width 0.088646)
		(layer "In11.Cu")
		(net "M_D_CPU0_SB_CA<5>")
	)
	(segment
		(start 300.914816 -248.907046)
		(end 300.25721 -248.907046)
		(width 0.18288)
		(layer "In11.Cu")
		(net "M_D_CPU0_SB_CA<5>")
	)
	(segment
		(start 293.296086 -248.741184)
		(end 293.04996 -248.741184)
		(width 0.18288)
		(layer "In11.Cu")
		(net "M_D_CPU0_SB_CA<5>")
	)
	(segment
		(start 305.765962 -247.818656)
		(end 305.765962 -247.694704)
		(width 0.18288)
		(layer "In11.Cu")
		(net "M_D_CPU0_SB_CA<5>")
	)
	(segment
		(start 328.154792 -247.309386)
		(end 322.762118 -247.309386)
		(width 0.18288)
		(layer "In11.Cu")
		(net "M_D_CPU0_SB_CA<5>")
	)
	(segment
		(start 282.471114 -248.314972)
		(end 282.471114 -248.514616)
		(width 0.18288)
		(layer "In11.Cu")
		(net "M_D_CPU0_SB_CA<5>")
	)
	(segment
		(start 278.904192 -248.706386)
		(end 278.904192 -248.483882)
		(width 0.18288)
		(layer "In11.Cu")
		(net "M_D_CPU0_SB_CA<5>")
	)
	(segment
		(start 309.184802 -247.266206)
		(end 308.674262 -247.776746)
		(width 0.18288)
		(layer "In11.Cu")
		(net "M_D_CPU0_SB_CA<5>")
	)
	(segment
		(start 279.351994 -248.899426)
		(end 279.097232 -248.899426)
		(width 0.18288)
		(layer "In11.Cu")
		(net "M_D_CPU0_SB_CA<5>")
	)
	(segment
		(start 289.883088 -248.943876)
		(end 289.883088 -248.849388)
		(width 0.18288)
		(layer "In11.Cu")
		(net "M_D_CPU0_SB_CA<5>")
	)
	(segment
		(start 271.76476 -248.975626)
		(end 271.57172 -248.782586)
		(width 0.18288)
		(layer "In11.Cu")
		(net "M_D_CPU0_SB_CA<5>")
	)
	(segment
		(start 331.963776 -248.018808)
		(end 331.812138 -247.86717)
		(width 0.088646)
		(layer "In11.Cu")
		(net "M_D_CPU0_SB_CA<5>")
	)
	(segment
		(start 342.381332 -248.316496)
		(end 342.381078 -248.316496)
		(width 0.088646)
		(layer "In11.Cu")
		(net "M_D_CPU0_SB_CA<5>")
	)
	(segment
		(start 290.584128 -248.849388)
		(end 290.584128 -248.943876)
		(width 0.18288)
		(layer "In11.Cu")
		(net "M_D_CPU0_SB_CA<5>")
	)
	(segment
		(start 291.979858 -248.656348)
		(end 290.777168 -248.656348)
		(width 0.18288)
		(layer "In11.Cu")
		(net "M_D_CPU0_SB_CA<5>")
	)
	(segment
		(start 332.292452 -248.018808)
		(end 331.963776 -248.018808)
		(width 0.088646)
		(layer "In11.Cu")
		(net "M_D_CPU0_SB_CA<5>")
	)
	(segment
		(start 342.006682 -248.316496)
		(end 341.99195 -248.30786)
		(width 0.088646)
		(layer "In11.Cu")
		(net "M_D_CPU0_SB_CA<5>")
	)
	(segment
		(start 274.989036 -249.299476)
		(end 274.284186 -248.594626)
		(width 0.18288)
		(layer "In11.Cu")
		(net "M_D_CPU0_SB_CA<5>")
	)
	(segment
		(start 271.57172 -248.782586)
		(end 271.57172 -248.462546)
		(width 0.18288)
		(layer "In11.Cu")
		(net "M_D_CPU0_SB_CA<5>")
	)
	(segment
		(start 274.284186 -248.594626)
		(end 273.330162 -248.594626)
		(width 0.18288)
		(layer "In11.Cu")
		(net "M_D_CPU0_SB_CA<5>")
	)
	(segment
		(start 303.518824 -248.011696)
		(end 302.623474 -248.907046)
		(width 0.18288)
		(layer "In11.Cu")
		(net "M_D_CPU0_SB_CA<5>")
	)
	(segment
		(start 304.871882 -248.011696)
		(end 303.518824 -248.011696)
		(width 0.18288)
		(layer "In11.Cu")
		(net "M_D_CPU0_SB_CA<5>")
	)
	(segment
		(start 278.203152 -248.483882)
		(end 278.203152 -248.706386)
		(width 0.18288)
		(layer "In11.Cu")
		(net "M_D_CPU0_SB_CA<5>")
	)
	(segment
		(start 316.079378 -248.080022)
		(end 314.460128 -246.460772)
		(width 0.18288)
		(layer "In11.Cu")
		(net "M_D_CPU0_SB_CA<5>")
	)
	(segment
		(start 295.900094 -248.741184)
		(end 294.383206 -248.741184)
		(width 0.18288)
		(layer "In11.Cu")
		(net "M_D_CPU0_SB_CA<5>")
	)
	(segment
		(start 276.937216 -248.675906)
		(end 276.081998 -248.675906)
		(width 0.18288)
		(layer "In11.Cu")
		(net "M_D_CPU0_SB_CA<5>")
	)
	(segment
		(start 282.278074 -248.707656)
		(end 281.274266 -248.707656)
		(width 0.18288)
		(layer "In11.Cu")
		(net "M_D_CPU0_SB_CA<5>")
	)
	(segment
		(start 305.064922 -247.694704)
		(end 305.064922 -247.818656)
		(width 0.18288)
		(layer "In11.Cu")
		(net "M_D_CPU0_SB_CA<5>")
	)
	(segment
		(start 305.064922 -247.818656)
		(end 304.871882 -248.011696)
		(width 0.18288)
		(layer "In11.Cu")
		(net "M_D_CPU0_SB_CA<5>")
	)
	(segment
		(start 342.390222 -248.311416)
		(end 342.381332 -248.316496)
		(width 0.088646)
		(layer "In11.Cu")
		(net "M_D_CPU0_SB_CA<5>")
	)
	(segment
		(start 287.619694 -248.874026)
		(end 284.577536 -248.874026)
		(width 0.18288)
		(layer "In11.Cu")
		(net "M_D_CPU0_SB_CA<5>")
	)
	(segment
		(start 279.097232 -248.899426)
		(end 278.904192 -248.706386)
		(width 0.18288)
		(layer "In11.Cu")
		(net "M_D_CPU0_SB_CA<5>")
	)
	(segment
		(start 341.066882 -248.316496)
		(end 341.05215 -248.30786)
		(width 0.088646)
		(layer "In11.Cu")
		(net "M_D_CPU0_SB_CA<5>")
	)
	(segment
		(start 305.257962 -247.501664)
		(end 305.064922 -247.694704)
		(width 0.18288)
		(layer "In11.Cu")
		(net "M_D_CPU0_SB_CA<5>")
	)
	(segment
		(start 278.010112 -248.899426)
		(end 277.160736 -248.899426)
		(width 0.18288)
		(layer "In11.Cu")
		(net "M_D_CPU0_SB_CA<5>")
	)
	(segment
		(start 290.391088 -249.136916)
		(end 290.076128 -249.136916)
		(width 0.18288)
		(layer "In11.Cu")
		(net "M_D_CPU0_SB_CA<5>")
	)
	(segment
		(start 290.584128 -248.943876)
		(end 290.391088 -249.136916)
		(width 0.18288)
		(layer "In11.Cu")
		(net "M_D_CPU0_SB_CA<5>")
	)
	(segment
		(start 270.87068 -248.782586)
		(end 270.67764 -248.975626)
		(width 0.18288)
		(layer "In11.Cu")
		(net "M_D_CPU0_SB_CA<5>")
	)
	(segment
		(start 302.001936 -248.907046)
		(end 301.808896 -248.714006)
		(width 0.18288)
		(layer "In11.Cu")
		(net "M_D_CPU0_SB_CA<5>")
	)
	(segment
		(start 322.762118 -247.309386)
		(end 321.991482 -248.080022)
		(width 0.18288)
		(layer "In11.Cu")
		(net "M_D_CPU0_SB_CA<5>")
	)
	(segment
		(start 340.127082 -248.316496)
		(end 340.116668 -248.3104)
		(width 0.088646)
		(layer "In11.Cu")
		(net "M_D_CPU0_SB_CA<5>")
	)
	(segment
		(start 283.172154 -248.548144)
		(end 283.172154 -248.314972)
		(width 0.18288)
		(layer "In11.Cu")
		(net "M_D_CPU0_SB_CA<5>")
	)
	(segment
		(start 283.172154 -248.314972)
		(end 282.979114 -248.121932)
		(width 0.18288)
		(layer "In11.Cu")
		(net "M_D_CPU0_SB_CA<5>")
	)
	(segment
		(start 282.471114 -248.514616)
		(end 282.278074 -248.707656)
		(width 0.18288)
		(layer "In11.Cu")
		(net "M_D_CPU0_SB_CA<5>")
	)
	(segment
		(start 339.187536 -248.316496)
		(end 339.177122 -248.3104)
		(width 0.088646)
		(layer "In11.Cu")
		(net "M_D_CPU0_SB_CA<5>")
	)
	(segment
		(start 290.076128 -249.136916)
		(end 289.883088 -248.943876)
		(width 0.18288)
		(layer "In11.Cu")
		(net "M_D_CPU0_SB_CA<5>")
	)
	(segment
		(start 271.37868 -248.269506)
		(end 271.06372 -248.269506)
		(width 0.18288)
		(layer "In11.Cu")
		(net "M_D_CPU0_SB_CA<5>")
	)
	(segment
		(start 277.160736 -248.899426)
		(end 276.937216 -248.675906)
		(width 0.18288)
		(layer "In11.Cu")
		(net "M_D_CPU0_SB_CA<5>")
	)
	(segment
		(start 276.081998 -248.675906)
		(end 275.458428 -249.299476)
		(width 0.18288)
		(layer "In11.Cu")
		(net "M_D_CPU0_SB_CA<5>")
	)
	(segment
		(start 338.247482 -248.316496)
		(end 338.237068 -248.3104)
		(width 0.088646)
		(layer "In11.Cu")
		(net "M_D_CPU0_SB_CA<5>")
	)
	(segment
		(start 284.577536 -248.874026)
		(end 284.444694 -248.741184)
		(width 0.18288)
		(layer "In11.Cu")
		(net "M_D_CPU0_SB_CA<5>")
	)
	(segment
		(start 305.765962 -247.694704)
		(end 305.572922 -247.501664)
		(width 0.18288)
		(layer "In11.Cu")
		(net "M_D_CPU0_SB_CA<5>")
	)
	(segment
		(start 301.107856 -248.596912)
		(end 301.107856 -248.714006)
		(width 0.18288)
		(layer "In11.Cu")
		(net "M_D_CPU0_SB_CA<5>")
	)
	(segment
		(start 297.544998 -248.74093)
		(end 297.322494 -248.518426)
		(width 0.18288)
		(layer "In11.Cu")
		(net "M_D_CPU0_SB_CA<5>")
	)
	(segment
		(start 301.808896 -248.714006)
		(end 301.808896 -248.596912)
		(width 0.18288)
		(layer "In11.Cu")
		(net "M_D_CPU0_SB_CA<5>")
	)
	(segment
		(start 300.25721 -248.907046)
		(end 300.091094 -248.74093)
		(width 0.18288)
		(layer "In11.Cu")
		(net "M_D_CPU0_SB_CA<5>")
	)
	(segment
		(start 292.917118 -248.874026)
		(end 292.197536 -248.874026)
		(width 0.18288)
		(layer "In11.Cu")
		(net "M_D_CPU0_SB_CA<5>")
	)
	(segment
		(start 331.614018 -247.86717)
		(end 328.712576 -247.86717)
		(width 0.18288)
		(layer "In11.Cu")
		(net "M_D_CPU0_SB_CA<5>")
	)
	(segment
		(start 289.690048 -248.656348)
		(end 287.837372 -248.656348)
		(width 0.18288)
		(layer "In11.Cu")
		(net "M_D_CPU0_SB_CA<5>")
	)
	(segment
		(start 310.248554 -247.266206)
		(end 309.184802 -247.266206)
		(width 0.18288)
		(layer "In11.Cu")
		(net "M_D_CPU0_SB_CA<5>")
	)
	(segment
		(start 271.06372 -248.269506)
		(end 270.87068 -248.462546)
		(width 0.18288)
		(layer "In11.Cu")
		(net "M_D_CPU0_SB_CA<5>")
	)
	(segment
		(start 307.379624 -248.011696)
		(end 305.959002 -248.011696)
		(width 0.18288)
		(layer "In11.Cu")
		(net "M_D_CPU0_SB_CA<5>")
	)
	(segment
		(start 297.322494 -248.518426)
		(end 296.122852 -248.518426)
		(width 0.18288)
		(layer "In11.Cu")
		(net "M_D_CPU0_SB_CA<5>")
	)
	(segment
		(start 272.949162 -248.975626)
		(end 271.76476 -248.975626)
		(width 0.18288)
		(layer "In11.Cu")
		(net "M_D_CPU0_SB_CA<5>")
	)
	(segment
		(start 283.365194 -248.741184)
		(end 283.172154 -248.548144)
		(width 0.18288)
		(layer "In11.Cu")
		(net "M_D_CPU0_SB_CA<5>")
	)
	(segment
		(start 301.808896 -248.596912)
		(end 301.615856 -248.403872)
		(width 0.18288)
		(layer "In11.Cu")
		(net "M_D_CPU0_SB_CA<5>")
	)
	(segment
		(start 270.87068 -248.462546)
		(end 270.87068 -248.782586)
		(width 0.18288)
		(layer "In11.Cu")
		(net "M_D_CPU0_SB_CA<5>")
	)
	(segment
		(start 279.510236 -248.741184)
		(end 279.351994 -248.899426)
		(width 0.18288)
		(layer "In11.Cu")
		(net "M_D_CPU0_SB_CA<5>")
	)
	(segment
		(start 287.837372 -248.656348)
		(end 287.619694 -248.874026)
		(width 0.18288)
		(layer "In11.Cu")
		(net "M_D_CPU0_SB_CA<5>")
	)
	(segment
		(start 284.444694 -248.741184)
		(end 283.365194 -248.741184)
		(width 0.18288)
		(layer "In11.Cu")
		(net "M_D_CPU0_SB_CA<5>")
	)
	(segment
		(start 331.812138 -247.86717)
		(end 331.614018 -247.86717)
		(width 0.088646)
		(layer "In11.Cu")
		(net "M_D_CPU0_SB_CA<5>")
	)
	(arc
		(start 341.99195 -248.30786)
		(mid 341.715509 -248.240694)
		(end 341.441278 -248.316496)
		(width 0.088646)
		(layer "In11.Cu")
		(net "M_D_CPU0_SB_CA<5>")
	)
	(arc
		(start 340.501478 -248.316496)
		(mid 340.31428 -248.366639)
		(end 340.127082 -248.316496)
		(width 0.088646)
		(layer "In11.Cu")
		(net "M_D_CPU0_SB_CA<5>")
	)
	(arc
		(start 338.237068 -248.3104)
		(mid 337.95889 -248.240708)
		(end 337.682332 -248.316496)
		(width 0.088646)
		(layer "In11.Cu")
		(net "M_D_CPU0_SB_CA<5>")
	)
	(arc
		(start 343.876122 -247.673876)
		(mid 343.59769 -247.743722)
		(end 343.320878 -247.66778)
		(width 0.088646)
		(layer "In11.Cu")
		(net "M_D_CPU0_SB_CA<5>")
	)
	(arc
		(start 334.488536 -248.316496)
		(mid 334.205834 -248.240754)
		(end 333.923132 -248.316496)
		(width 0.088646)
		(layer "In11.Cu")
		(net "M_D_CPU0_SB_CA<5>")
	)
	(arc
		(start 333.548736 -248.316496)
		(mid 333.266034 -248.240754)
		(end 332.983332 -248.316496)
		(width 0.088646)
		(layer "In11.Cu")
		(net "M_D_CPU0_SB_CA<5>")
	)
	(arc
		(start 336.742278 -248.316496)
		(mid 336.55508 -248.366639)
		(end 336.367882 -248.316496)
		(width 0.088646)
		(layer "In11.Cu")
		(net "M_D_CPU0_SB_CA<5>")
	)
	(arc
		(start 337.682332 -248.316496)
		(mid 337.495134 -248.366639)
		(end 337.307936 -248.316496)
		(width 0.088646)
		(layer "In11.Cu")
		(net "M_D_CPU0_SB_CA<5>")
	)
	(arc
		(start 336.357468 -248.3104)
		(mid 336.07929 -248.240708)
		(end 335.802732 -248.316496)
		(width 0.088646)
		(layer "In11.Cu")
		(net "M_D_CPU0_SB_CA<5>")
	)
	(arc
		(start 334.862932 -248.316496)
		(mid 334.675734 -248.366639)
		(end 334.488536 -248.316496)
		(width 0.088646)
		(layer "In11.Cu")
		(net "M_D_CPU0_SB_CA<5>")
	)
	(arc
		(start 341.05215 -248.30786)
		(mid 340.775709 -248.240694)
		(end 340.501478 -248.316496)
		(width 0.088646)
		(layer "In11.Cu")
		(net "M_D_CPU0_SB_CA<5>")
	)
	(arc
		(start 345.148662 -247.643142)
		(mid 344.984566 -247.618795)
		(end 344.826082 -247.66778)
		(width 0.088646)
		(layer "In11.Cu")
		(net "M_D_CPU0_SB_CA<5>")
	)
	(arc
		(start 338.621878 -248.316496)
		(mid 338.43468 -248.366639)
		(end 338.247482 -248.316496)
		(width 0.088646)
		(layer "In11.Cu")
		(net "M_D_CPU0_SB_CA<5>")
	)
	(arc
		(start 339.561932 -248.316496)
		(mid 339.374734 -248.366639)
		(end 339.187536 -248.316496)
		(width 0.088646)
		(layer "In11.Cu")
		(net "M_D_CPU0_SB_CA<5>")
	)
	(arc
		(start 332.983332 -248.316496)
		(mid 332.796134 -248.366639)
		(end 332.608936 -248.316496)
		(width 0.088646)
		(layer "In11.Cu")
		(net "M_D_CPU0_SB_CA<5>")
	)
	(arc
		(start 333.923132 -248.316496)
		(mid 333.735934 -248.366639)
		(end 333.548736 -248.316496)
		(width 0.088646)
		(layer "In11.Cu")
		(net "M_D_CPU0_SB_CA<5>")
	)
	(arc
		(start 335.428336 -248.316496)
		(mid 335.145634 -248.240754)
		(end 334.862932 -248.316496)
		(width 0.088646)
		(layer "In11.Cu")
		(net "M_D_CPU0_SB_CA<5>")
	)
	(arc
		(start 337.297522 -248.3104)
		(mid 337.01909 -248.240586)
		(end 336.742278 -248.316496)
		(width 0.088646)
		(layer "In11.Cu")
		(net "M_D_CPU0_SB_CA<5>")
	)
	(arc
		(start 342.67648 -247.884442)
		(mid 342.602336 -247.98061)
		(end 342.555068 -248.092468)
		(width 0.088646)
		(layer "In11.Cu")
		(net "M_D_CPU0_SB_CA<5>")
	)
	(arc
		(start 342.555068 -248.092468)
		(mid 342.493362 -248.217532)
		(end 342.390222 -248.311416)
		(width 0.088646)
		(layer "In11.Cu")
		(net "M_D_CPU0_SB_CA<5>")
	)
	(arc
		(start 339.177122 -248.3104)
		(mid 338.89869 -248.240586)
		(end 338.621878 -248.316496)
		(width 0.088646)
		(layer "In11.Cu")
		(net "M_D_CPU0_SB_CA<5>")
	)
	(arc
		(start 344.260932 -247.66778)
		(mid 344.073734 -247.617637)
		(end 343.886536 -247.66778)
		(width 0.088646)
		(layer "In11.Cu")
		(net "M_D_CPU0_SB_CA<5>")
	)
	(arc
		(start 342.381078 -248.316496)
		(mid 342.19388 -248.366639)
		(end 342.006682 -248.316496)
		(width 0.088646)
		(layer "In11.Cu")
		(net "M_D_CPU0_SB_CA<5>")
	)
	(arc
		(start 342.946482 -247.66778)
		(mid 342.826168 -247.748155)
		(end 342.717374 -247.843548)
		(width 0.088646)
		(layer "In11.Cu")
		(net "M_D_CPU0_SB_CA<5>")
	)
	(arc
		(start 332.608936 -248.316496)
		(mid 332.568006 -248.289463)
		(end 332.530958 -248.257314)
		(width 0.088646)
		(layer "In11.Cu")
		(net "M_D_CPU0_SB_CA<5>")
	)
	(arc
		(start 343.320878 -247.66778)
		(mid 343.13368 -247.617637)
		(end 342.946482 -247.66778)
		(width 0.088646)
		(layer "In11.Cu")
		(net "M_D_CPU0_SB_CA<5>")
	)
	(arc
		(start 341.441278 -248.316496)
		(mid 341.25408 -248.366639)
		(end 341.066882 -248.316496)
		(width 0.088646)
		(layer "In11.Cu")
		(net "M_D_CPU0_SB_CA<5>")
	)
	(arc
		(start 344.826082 -247.66778)
		(mid 344.549523 -247.743523)
		(end 344.271346 -247.673876)
		(width 0.088646)
		(layer "In11.Cu")
		(net "M_D_CPU0_SB_CA<5>")
	)
	(arc
		(start 335.802732 -248.316496)
		(mid 335.615534 -248.366639)
		(end 335.428336 -248.316496)
		(width 0.088646)
		(layer "In11.Cu")
		(net "M_D_CPU0_SB_CA<5>")
	)
	(arc
		(start 340.116668 -248.3104)
		(mid 339.83849 -248.240708)
		(end 339.561932 -248.316496)
		(width 0.088646)
		(layer "In11.Cu")
		(net "M_D_CPU0_SB_CA<5>")
	)
	(segment
		(start 258.44754 -248.732802)
		(end 258.28498 -248.895362)
		(width 0.20066)
		(layer "F.Cu")
		(net "M_D_CPU0_SB_CA<4>")
	)
	(segment
		(start 258.28498 -249.22353)
		(end 258.130548 -249.377962)
		(width 0.20066)
		(layer "F.Cu")
		(net "M_D_CPU0_SB_CA<4>")
	)
	(segment
		(start 261.381494 -248.741692)
		(end 261.050786 -248.741692)
		(width 0.101854)
		(layer "F.Cu")
		(net "M_D_CPU0_SB_CA<4>")
	)
	(segment
		(start 258.130548 -249.377962)
		(end 257.626104 -249.377962)
		(width 0.20066)
		(layer "F.Cu")
		(net "M_D_CPU0_SB_CA<4>")
	)
	(segment
		(start 343.133934 -248.528078)
		(end 343.13368 -248.527824)
		(width 0.20066)
		(layer "F.Cu")
		(net "M_D_CPU0_SB_CA<4>")
	)
	(segment
		(start 261.050786 -248.741692)
		(end 259.065268 -248.741692)
		(width 0.1016)
		(layer "F.Cu")
		(net "M_D_CPU0_SB_CA<4>")
	)
	(segment
		(start 263.624314 -249.166634)
		(end 261.984998 -249.166634)
		(width 0.20066)
		(layer "F.Cu")
		(net "M_D_CPU0_SB_CA<4>")
	)
	(segment
		(start 343.13368 -248.527824)
		(end 343.13368 -247.992138)
		(width 0.20066)
		(layer "F.Cu")
		(net "M_D_CPU0_SB_CA<4>")
	)
	(segment
		(start 261.560056 -248.741692)
		(end 261.381494 -248.741692)
		(width 0.20066)
		(layer "F.Cu")
		(net "M_D_CPU0_SB_CA<4>")
	)
	(segment
		(start 257.626104 -249.377962)
		(end 257.414776 -249.166634)
		(width 0.20066)
		(layer "F.Cu")
		(net "M_D_CPU0_SB_CA<4>")
	)
	(segment
		(start 258.28498 -248.895362)
		(end 258.28498 -249.22353)
		(width 0.20066)
		(layer "F.Cu")
		(net "M_D_CPU0_SB_CA<4>")
	)
	(segment
		(start 259.056378 -248.732802)
		(end 258.44754 -248.732802)
		(width 0.20066)
		(layer "F.Cu")
		(net "M_D_CPU0_SB_CA<4>")
	)
	(segment
		(start 261.984998 -249.166634)
		(end 261.560056 -248.741692)
		(width 0.20066)
		(layer "F.Cu")
		(net "M_D_CPU0_SB_CA<4>")
	)
	(segment
		(start 259.065268 -248.741692)
		(end 259.056378 -248.732802)
		(width 0.1016)
		(layer "F.Cu")
		(net "M_D_CPU0_SB_CA<4>")
	)
	(segment
		(start 264.729214 -249.166634)
		(end 263.624314 -249.166634)
		(width 0.20066)
		(layer "F.Cu")
		(net "M_D_CPU0_SB_CA<4>")
	)
	(segment
		(start 257.414776 -249.166634)
		(end 256.080514 -249.166634)
		(width 0.20066)
		(layer "F.Cu")
		(net "M_D_CPU0_SB_CA<4>")
	)
	(segment
		(start 305.753008 -249.108722)
		(end 305.559968 -249.301762)
		(width 0.18288)
		(layer "In11.Cu")
		(net "M_D_CPU0_SB_CA<4>")
	)
	(segment
		(start 269.816072 -249.509026)
		(end 269.734284 -249.590814)
		(width 0.18288)
		(layer "In11.Cu")
		(net "M_D_CPU0_SB_CA<4>")
	)
	(segment
		(start 265.153394 -249.590814)
		(end 264.729214 -249.166634)
		(width 0.18288)
		(layer "In11.Cu")
		(net "M_D_CPU0_SB_CA<4>")
	)
	(segment
		(start 299.995336 -249.440446)
		(end 299.844714 -249.591068)
		(width 0.18288)
		(layer "In11.Cu")
		(net "M_D_CPU0_SB_CA<4>")
	)
	(segment
		(start 331.614018 -248.24436)
		(end 328.60107 -248.24436)
		(width 0.18288)
		(layer "In11.Cu")
		(net "M_D_CPU0_SB_CA<4>")
	)
	(segment
		(start 265.541252 -249.590814)
		(end 265.153394 -249.590814)
		(width 0.18288)
		(layer "In11.Cu")
		(net "M_D_CPU0_SB_CA<4>")
	)
	(segment
		(start 305.245008 -249.301762)
		(end 305.051968 -249.108722)
		(width 0.18288)
		(layer "In11.Cu")
		(net "M_D_CPU0_SB_CA<4>")
	)
	(segment
		(start 267.136372 -250.377452)
		(end 267.136372 -249.802904)
		(width 0.18288)
		(layer "In11.Cu")
		(net "M_D_CPU0_SB_CA<4>")
	)
	(segment
		(start 267.136372 -249.802904)
		(end 266.943332 -249.609864)
		(width 0.18288)
		(layer "In11.Cu")
		(net "M_D_CPU0_SB_CA<4>")
	)
	(segment
		(start 277.236936 -249.407426)
		(end 276.980396 -249.663966)
		(width 0.18288)
		(layer "In11.Cu")
		(net "M_D_CPU0_SB_CA<4>")
	)
	(segment
		(start 266.628372 -249.609864)
		(end 266.435332 -249.802904)
		(width 0.18288)
		(layer "In11.Cu")
		(net "M_D_CPU0_SB_CA<4>")
	)
	(segment
		(start 322.201794 -248.58853)
		(end 315.838586 -248.58853)
		(width 0.18288)
		(layer "In11.Cu")
		(net "M_D_CPU0_SB_CA<4>")
	)
	(segment
		(start 274.82419 -250.050554)
		(end 274.477988 -249.704352)
		(width 0.18288)
		(layer "In11.Cu")
		(net "M_D_CPU0_SB_CA<4>")
	)
	(segment
		(start 278.145494 -249.407426)
		(end 277.236936 -249.407426)
		(width 0.18288)
		(layer "In11.Cu")
		(net "M_D_CPU0_SB_CA<4>")
	)
	(segment
		(start 272.519394 -249.509026)
		(end 269.816072 -249.509026)
		(width 0.18288)
		(layer "In11.Cu")
		(net "M_D_CPU0_SB_CA<4>")
	)
	(segment
		(start 328.011536 -247.654826)
		(end 323.135498 -247.654826)
		(width 0.18288)
		(layer "In11.Cu")
		(net "M_D_CPU0_SB_CA<4>")
	)
	(segment
		(start 267.644372 -250.570492)
		(end 267.329412 -250.570492)
		(width 0.18288)
		(layer "In11.Cu")
		(net "M_D_CPU0_SB_CA<4>")
	)
	(segment
		(start 314.244482 -246.994426)
		(end 311.462674 -246.994426)
		(width 0.18288)
		(layer "In11.Cu")
		(net "M_D_CPU0_SB_CA<4>")
	)
	(segment
		(start 295.823894 -249.591068)
		(end 294.599868 -249.591068)
		(width 0.18288)
		(layer "In11.Cu")
		(net "M_D_CPU0_SB_CA<4>")
	)
	(segment
		(start 276.980396 -249.663966)
		(end 275.960586 -249.663966)
		(width 0.18288)
		(layer "In11.Cu")
		(net "M_D_CPU0_SB_CA<4>")
	)
	(segment
		(start 267.837412 -249.783854)
		(end 267.837412 -250.377452)
		(width 0.18288)
		(layer "In11.Cu")
		(net "M_D_CPU0_SB_CA<4>")
	)
	(segment
		(start 275.960586 -249.663966)
		(end 275.573998 -250.050554)
		(width 0.18288)
		(layer "In11.Cu")
		(net "M_D_CPU0_SB_CA<4>")
	)
	(segment
		(start 309.461154 -247.819926)
		(end 308.414674 -248.866406)
		(width 0.18288)
		(layer "In11.Cu")
		(net "M_D_CPU0_SB_CA<4>")
	)
	(segment
		(start 266.435332 -249.802904)
		(end 266.435332 -250.377452)
		(width 0.18288)
		(layer "In11.Cu")
		(net "M_D_CPU0_SB_CA<4>")
	)
	(segment
		(start 294.441626 -249.432826)
		(end 292.070536 -249.432826)
		(width 0.18288)
		(layer "In11.Cu")
		(net "M_D_CPU0_SB_CA<4>")
	)
	(segment
		(start 328.60107 -248.24436)
		(end 328.011536 -247.654826)
		(width 0.18288)
		(layer "In11.Cu")
		(net "M_D_CPU0_SB_CA<4>")
	)
	(segment
		(start 306.870354 -248.538746)
		(end 305.946048 -248.538746)
		(width 0.18288)
		(layer "In11.Cu")
		(net "M_D_CPU0_SB_CA<4>")
	)
	(segment
		(start 323.135498 -247.654826)
		(end 322.201794 -248.58853)
		(width 0.18288)
		(layer "In11.Cu")
		(net "M_D_CPU0_SB_CA<4>")
	)
	(segment
		(start 266.242292 -250.570492)
		(end 265.927332 -250.570492)
		(width 0.18288)
		(layer "In11.Cu")
		(net "M_D_CPU0_SB_CA<4>")
	)
	(segment
		(start 305.946048 -248.538746)
		(end 305.753008 -248.731786)
		(width 0.18288)
		(layer "In11.Cu")
		(net "M_D_CPU0_SB_CA<4>")
	)
	(segment
		(start 288.381694 -249.458226)
		(end 284.780736 -249.458226)
		(width 0.18288)
		(layer "In11.Cu")
		(net "M_D_CPU0_SB_CA<4>")
	)
	(segment
		(start 281.271218 -249.591068)
		(end 278.329136 -249.591068)
		(width 0.18288)
		(layer "In11.Cu")
		(net "M_D_CPU0_SB_CA<4>")
	)
	(segment
		(start 265.927332 -250.570492)
		(end 265.734292 -250.377452)
		(width 0.18288)
		(layer "In11.Cu")
		(net "M_D_CPU0_SB_CA<4>")
	)
	(segment
		(start 299.844714 -249.591068)
		(end 297.367452 -249.591068)
		(width 0.18288)
		(layer "In11.Cu")
		(net "M_D_CPU0_SB_CA<4>")
	)
	(segment
		(start 341.921846 -248.487946)
		(end 341.911432 -248.48185)
		(width 0.088646)
		(layer "In11.Cu")
		(net "M_D_CPU0_SB_CA<4>")
	)
	(segment
		(start 304.858928 -248.538746)
		(end 303.817274 -248.538746)
		(width 0.18288)
		(layer "In11.Cu")
		(net "M_D_CPU0_SB_CA<4>")
	)
	(segment
		(start 336.287364 -248.490486)
		(end 336.272632 -248.48185)
		(width 0.088646)
		(layer "In11.Cu")
		(net "M_D_CPU0_SB_CA<4>")
	)
	(segment
		(start 305.753008 -248.731786)
		(end 305.753008 -249.108722)
		(width 0.18288)
		(layer "In11.Cu")
		(net "M_D_CPU0_SB_CA<4>")
	)
	(segment
		(start 294.599868 -249.591068)
		(end 294.441626 -249.432826)
		(width 0.18288)
		(layer "In11.Cu")
		(net "M_D_CPU0_SB_CA<4>")
	)
	(segment
		(start 340.046564 -248.490486)
		(end 340.031832 -248.48185)
		(width 0.088646)
		(layer "In11.Cu")
		(net "M_D_CPU0_SB_CA<4>")
	)
	(segment
		(start 308.414674 -248.866406)
		(end 307.198014 -248.866406)
		(width 0.18288)
		(layer "In11.Cu")
		(net "M_D_CPU0_SB_CA<4>")
	)
	(segment
		(start 310.637174 -247.819926)
		(end 309.461154 -247.819926)
		(width 0.18288)
		(layer "In11.Cu")
		(net "M_D_CPU0_SB_CA<4>")
	)
	(segment
		(start 274.477988 -249.704352)
		(end 272.71472 -249.704352)
		(width 0.18288)
		(layer "In11.Cu")
		(net "M_D_CPU0_SB_CA<4>")
	)
	(segment
		(start 272.71472 -249.704352)
		(end 272.519394 -249.509026)
		(width 0.18288)
		(layer "In11.Cu")
		(net "M_D_CPU0_SB_CA<4>")
	)
	(segment
		(start 297.253914 -249.704606)
		(end 295.937432 -249.704606)
		(width 0.18288)
		(layer "In11.Cu")
		(net "M_D_CPU0_SB_CA<4>")
	)
	(segment
		(start 297.367452 -249.591068)
		(end 297.253914 -249.704606)
		(width 0.18288)
		(layer "In11.Cu")
		(net "M_D_CPU0_SB_CA<4>")
	)
	(segment
		(start 311.462674 -246.994426)
		(end 310.637174 -247.819926)
		(width 0.18288)
		(layer "In11.Cu")
		(net "M_D_CPU0_SB_CA<4>")
	)
	(segment
		(start 295.937432 -249.704606)
		(end 295.823894 -249.591068)
		(width 0.18288)
		(layer "In11.Cu")
		(net "M_D_CPU0_SB_CA<4>")
	)
	(segment
		(start 332.248764 -248.24436)
		(end 331.614018 -248.24436)
		(width 0.088646)
		(layer "In11.Cu")
		(net "M_D_CPU0_SB_CA<4>")
	)
	(segment
		(start 292.070536 -249.432826)
		(end 291.832792 -249.67057)
		(width 0.18288)
		(layer "In11.Cu")
		(net "M_D_CPU0_SB_CA<4>")
	)
	(segment
		(start 332.396338 -248.391934)
		(end 332.248764 -248.24436)
		(width 0.088646)
		(layer "In11.Cu")
		(net "M_D_CPU0_SB_CA<4>")
	)
	(segment
		(start 338.166964 -248.490486)
		(end 338.152232 -248.48185)
		(width 0.088646)
		(layer "In11.Cu")
		(net "M_D_CPU0_SB_CA<4>")
	)
	(segment
		(start 302.915574 -249.440446)
		(end 299.995336 -249.440446)
		(width 0.18288)
		(layer "In11.Cu")
		(net "M_D_CPU0_SB_CA<4>")
	)
	(segment
		(start 305.051968 -249.108722)
		(end 305.051968 -248.731786)
		(width 0.18288)
		(layer "In11.Cu")
		(net "M_D_CPU0_SB_CA<4>")
	)
	(segment
		(start 267.837412 -250.377452)
		(end 267.644372 -250.570492)
		(width 0.18288)
		(layer "In11.Cu")
		(net "M_D_CPU0_SB_CA<4>")
	)
	(segment
		(start 307.198014 -248.866406)
		(end 306.870354 -248.538746)
		(width 0.18288)
		(layer "In11.Cu")
		(net "M_D_CPU0_SB_CA<4>")
	)
	(segment
		(start 282.209494 -249.712226)
		(end 281.392376 -249.712226)
		(width 0.18288)
		(layer "In11.Cu")
		(net "M_D_CPU0_SB_CA<4>")
	)
	(segment
		(start 284.780736 -249.458226)
		(end 284.647894 -249.591068)
		(width 0.18288)
		(layer "In11.Cu")
		(net "M_D_CPU0_SB_CA<4>")
	)
	(segment
		(start 342.552782 -248.437908)
		(end 342.476582 -248.48185)
		(width 0.088646)
		(layer "In11.Cu")
		(net "M_D_CPU0_SB_CA<4>")
	)
	(segment
		(start 288.594038 -249.67057)
		(end 288.381694 -249.458226)
		(width 0.18288)
		(layer "In11.Cu")
		(net "M_D_CPU0_SB_CA<4>")
	)
	(segment
		(start 268.030452 -249.590814)
		(end 267.837412 -249.783854)
		(width 0.18288)
		(layer "In11.Cu")
		(net "M_D_CPU0_SB_CA<4>")
	)
	(segment
		(start 267.329412 -250.570492)
		(end 267.136372 -250.377452)
		(width 0.18288)
		(layer "In11.Cu")
		(net "M_D_CPU0_SB_CA<4>")
	)
	(segment
		(start 340.986364 -248.490486)
		(end 340.971632 -248.48185)
		(width 0.088646)
		(layer "In11.Cu")
		(net "M_D_CPU0_SB_CA<4>")
	)
	(segment
		(start 305.051968 -248.731786)
		(end 304.858928 -248.538746)
		(width 0.18288)
		(layer "In11.Cu")
		(net "M_D_CPU0_SB_CA<4>")
	)
	(segment
		(start 266.435332 -250.377452)
		(end 266.242292 -250.570492)
		(width 0.18288)
		(layer "In11.Cu")
		(net "M_D_CPU0_SB_CA<4>")
	)
	(segment
		(start 282.330652 -249.591068)
		(end 282.209494 -249.712226)
		(width 0.18288)
		(layer "In11.Cu")
		(net "M_D_CPU0_SB_CA<4>")
	)
	(segment
		(start 284.647894 -249.591068)
		(end 282.330652 -249.591068)
		(width 0.18288)
		(layer "In11.Cu")
		(net "M_D_CPU0_SB_CA<4>")
	)
	(segment
		(start 303.817274 -248.538746)
		(end 302.915574 -249.440446)
		(width 0.18288)
		(layer "In11.Cu")
		(net "M_D_CPU0_SB_CA<4>")
	)
	(segment
		(start 281.392376 -249.712226)
		(end 281.271218 -249.591068)
		(width 0.18288)
		(layer "In11.Cu")
		(net "M_D_CPU0_SB_CA<4>")
	)
	(segment
		(start 265.734292 -250.377452)
		(end 265.734292 -249.783854)
		(width 0.18288)
		(layer "In11.Cu")
		(net "M_D_CPU0_SB_CA<4>")
	)
	(segment
		(start 278.329136 -249.591068)
		(end 278.145494 -249.407426)
		(width 0.18288)
		(layer "In11.Cu")
		(net "M_D_CPU0_SB_CA<4>")
	)
	(segment
		(start 315.838586 -248.58853)
		(end 314.244482 -246.994426)
		(width 0.18288)
		(layer "In11.Cu")
		(net "M_D_CPU0_SB_CA<4>")
	)
	(segment
		(start 269.734284 -249.590814)
		(end 268.030452 -249.590814)
		(width 0.18288)
		(layer "In11.Cu")
		(net "M_D_CPU0_SB_CA<4>")
	)
	(segment
		(start 275.573998 -250.050554)
		(end 274.82419 -250.050554)
		(width 0.18288)
		(layer "In11.Cu")
		(net "M_D_CPU0_SB_CA<4>")
	)
	(segment
		(start 265.734292 -249.783854)
		(end 265.541252 -249.590814)
		(width 0.18288)
		(layer "In11.Cu")
		(net "M_D_CPU0_SB_CA<4>")
	)
	(segment
		(start 291.832792 -249.67057)
		(end 288.594038 -249.67057)
		(width 0.18288)
		(layer "In11.Cu")
		(net "M_D_CPU0_SB_CA<4>")
	)
	(segment
		(start 305.559968 -249.301762)
		(end 305.245008 -249.301762)
		(width 0.18288)
		(layer "In11.Cu")
		(net "M_D_CPU0_SB_CA<4>")
	)
	(segment
		(start 266.943332 -249.609864)
		(end 266.628372 -249.609864)
		(width 0.18288)
		(layer "In11.Cu")
		(net "M_D_CPU0_SB_CA<4>")
	)
	(arc
		(start 340.597236 -248.48185)
		(mid 340.323007 -248.557775)
		(end 340.046564 -248.490486)
		(width 0.088646)
		(layer "In11.Cu")
		(net "M_D_CPU0_SB_CA<4>")
	)
	(arc
		(start 337.777836 -248.48185)
		(mid 337.495134 -248.557592)
		(end 337.212432 -248.48185)
		(width 0.088646)
		(layer "In11.Cu")
		(net "M_D_CPU0_SB_CA<4>")
	)
	(arc
		(start 340.031832 -248.48185)
		(mid 339.844634 -248.431707)
		(end 339.657436 -248.48185)
		(width 0.088646)
		(layer "In11.Cu")
		(net "M_D_CPU0_SB_CA<4>")
	)
	(arc
		(start 336.838036 -248.48185)
		(mid 336.563807 -248.557775)
		(end 336.287364 -248.490486)
		(width 0.088646)
		(layer "In11.Cu")
		(net "M_D_CPU0_SB_CA<4>")
	)
	(arc
		(start 333.453232 -248.48185)
		(mid 333.266034 -248.431707)
		(end 333.078836 -248.48185)
		(width 0.088646)
		(layer "In11.Cu")
		(net "M_D_CPU0_SB_CA<4>")
	)
	(arc
		(start 341.911432 -248.48185)
		(mid 341.724234 -248.431707)
		(end 341.537036 -248.48185)
		(width 0.088646)
		(layer "In11.Cu")
		(net "M_D_CPU0_SB_CA<4>")
	)
	(arc
		(start 338.717636 -248.48185)
		(mid 338.443407 -248.557775)
		(end 338.166964 -248.490486)
		(width 0.088646)
		(layer "In11.Cu")
		(net "M_D_CPU0_SB_CA<4>")
	)
	(arc
		(start 334.958436 -248.48185)
		(mid 334.675734 -248.557592)
		(end 334.393032 -248.48185)
		(width 0.088646)
		(layer "In11.Cu")
		(net "M_D_CPU0_SB_CA<4>")
	)
	(arc
		(start 343.13368 -247.992138)
		(mid 342.857844 -248.234067)
		(end 342.552782 -248.437908)
		(width 0.088646)
		(layer "In11.Cu")
		(net "M_D_CPU0_SB_CA<4>")
	)
	(arc
		(start 341.537036 -248.48185)
		(mid 341.262807 -248.557775)
		(end 340.986364 -248.490486)
		(width 0.088646)
		(layer "In11.Cu")
		(net "M_D_CPU0_SB_CA<4>")
	)
	(arc
		(start 334.393032 -248.48185)
		(mid 334.205834 -248.431707)
		(end 334.018636 -248.48185)
		(width 0.088646)
		(layer "In11.Cu")
		(net "M_D_CPU0_SB_CA<4>")
	)
	(arc
		(start 337.212432 -248.48185)
		(mid 337.025234 -248.431707)
		(end 336.838036 -248.48185)
		(width 0.088646)
		(layer "In11.Cu")
		(net "M_D_CPU0_SB_CA<4>")
	)
	(arc
		(start 333.078836 -248.48185)
		(mid 332.722313 -248.552753)
		(end 332.396338 -248.391934)
		(width 0.088646)
		(layer "In11.Cu")
		(net "M_D_CPU0_SB_CA<4>")
	)
	(arc
		(start 339.092032 -248.48185)
		(mid 338.904834 -248.431707)
		(end 338.717636 -248.48185)
		(width 0.088646)
		(layer "In11.Cu")
		(net "M_D_CPU0_SB_CA<4>")
	)
	(arc
		(start 335.898236 -248.48185)
		(mid 335.615534 -248.557592)
		(end 335.332832 -248.48185)
		(width 0.088646)
		(layer "In11.Cu")
		(net "M_D_CPU0_SB_CA<4>")
	)
	(arc
		(start 340.971632 -248.48185)
		(mid 340.784434 -248.431707)
		(end 340.597236 -248.48185)
		(width 0.088646)
		(layer "In11.Cu")
		(net "M_D_CPU0_SB_CA<4>")
	)
	(arc
		(start 342.476582 -248.48185)
		(mid 342.200023 -248.557559)
		(end 341.921846 -248.487946)
		(width 0.088646)
		(layer "In11.Cu")
		(net "M_D_CPU0_SB_CA<4>")
	)
	(arc
		(start 338.152232 -248.48185)
		(mid 337.965034 -248.431707)
		(end 337.777836 -248.48185)
		(width 0.088646)
		(layer "In11.Cu")
		(net "M_D_CPU0_SB_CA<4>")
	)
	(arc
		(start 339.657436 -248.48185)
		(mid 339.374734 -248.557592)
		(end 339.092032 -248.48185)
		(width 0.088646)
		(layer "In11.Cu")
		(net "M_D_CPU0_SB_CA<4>")
	)
	(arc
		(start 334.018636 -248.48185)
		(mid 333.735934 -248.557592)
		(end 333.453232 -248.48185)
		(width 0.088646)
		(layer "In11.Cu")
		(net "M_D_CPU0_SB_CA<4>")
	)
	(arc
		(start 336.272632 -248.48185)
		(mid 336.085434 -248.431707)
		(end 335.898236 -248.48185)
		(width 0.088646)
		(layer "In11.Cu")
		(net "M_D_CPU0_SB_CA<4>")
	)
	(arc
		(start 335.332832 -248.48185)
		(mid 335.145634 -248.431707)
		(end 334.958436 -248.48185)
		(width 0.088646)
		(layer "In11.Cu")
		(net "M_D_CPU0_SB_CA<4>")
	)
	(segment
		(start 262.514334 -250.441714)
		(end 262.50011 -250.455938)
		(width 0.101854)
		(layer "F.Cu")
		(net "M_D_CPU0_SB_CA<3>")
	)
	(segment
		(start 268.829282 -250.016772)
		(end 267.724382 -250.016772)
		(width 0.20066)
		(layer "F.Cu")
		(net "M_D_CPU0_SB_CA<3>")
	)
	(segment
		(start 262.003794 -250.313444)
		(end 262.003794 -250.142756)
		(width 0.20066)
		(layer "F.Cu")
		(net "M_D_CPU0_SB_CA<3>")
	)
	(segment
		(start 262.752332 -250.441714)
		(end 262.514334 -250.441714)
		(width 0.101854)
		(layer "F.Cu")
		(net "M_D_CPU0_SB_CA<3>")
	)
	(segment
		(start 262.146288 -250.455938)
		(end 262.003794 -250.313444)
		(width 0.20066)
		(layer "F.Cu")
		(net "M_D_CPU0_SB_CA<3>")
	)
	(segment
		(start 266.042394 -250.012454)
		(end 265.64717 -250.012454)
		(width 0.20066)
		(layer "F.Cu")
		(net "M_D_CPU0_SB_CA<3>")
	)
	(segment
		(start 344.543634 -249.341894)
		(end 344.543634 -248.806208)
		(width 0.20066)
		(layer "F.Cu")
		(net "M_D_CPU0_SB_CA<3>")
	)
	(segment
		(start 265.518646 -250.140978)
		(end 265.518646 -250.292616)
		(width 0.20066)
		(layer "F.Cu")
		(net "M_D_CPU0_SB_CA<3>")
	)
	(segment
		(start 265.369548 -250.441714)
		(end 264.825226 -250.441714)
		(width 0.20066)
		(layer "F.Cu")
		(net "M_D_CPU0_SB_CA<3>")
	)
	(segment
		(start 267.724382 -250.016772)
		(end 266.90828 -250.016772)
		(width 0.20066)
		(layer "F.Cu")
		(net "M_D_CPU0_SB_CA<3>")
	)
	(segment
		(start 265.64717 -250.012454)
		(end 265.518646 -250.140978)
		(width 0.20066)
		(layer "F.Cu")
		(net "M_D_CPU0_SB_CA<3>")
	)
	(segment
		(start 264.825226 -250.441714)
		(end 262.752332 -250.441714)
		(width 0.1016)
		(layer "F.Cu")
		(net "M_D_CPU0_SB_CA<3>")
	)
	(segment
		(start 266.25423 -250.22429)
		(end 266.042394 -250.012454)
		(width 0.20066)
		(layer "F.Cu")
		(net "M_D_CPU0_SB_CA<3>")
	)
	(segment
		(start 265.518646 -250.292616)
		(end 265.369548 -250.441714)
		(width 0.20066)
		(layer "F.Cu")
		(net "M_D_CPU0_SB_CA<3>")
	)
	(segment
		(start 266.700762 -250.22429)
		(end 266.25423 -250.22429)
		(width 0.20066)
		(layer "F.Cu")
		(net "M_D_CPU0_SB_CA<3>")
	)
	(segment
		(start 262.003794 -250.142756)
		(end 261.87781 -250.016772)
		(width 0.20066)
		(layer "F.Cu")
		(net "M_D_CPU0_SB_CA<3>")
	)
	(segment
		(start 261.87781 -250.016772)
		(end 260.180582 -250.016772)
		(width 0.20066)
		(layer "F.Cu")
		(net "M_D_CPU0_SB_CA<3>")
	)
	(segment
		(start 344.54338 -249.342148)
		(end 344.543634 -249.341894)
		(width 0.20066)
		(layer "F.Cu")
		(net "M_D_CPU0_SB_CA<3>")
	)
	(segment
		(start 266.90828 -250.016772)
		(end 266.700762 -250.22429)
		(width 0.20066)
		(layer "F.Cu")
		(net "M_D_CPU0_SB_CA<3>")
	)
	(segment
		(start 262.50011 -250.455938)
		(end 262.146288 -250.455938)
		(width 0.20066)
		(layer "F.Cu")
		(net "M_D_CPU0_SB_CA<3>")
	)
	(segment
		(start 270.844264 -250.227846)
		(end 270.844264 -250.36907)
		(width 0.18288)
		(layer "In11.Cu")
		(net "M_D_CPU0_SB_CA<3>")
	)
	(segment
		(start 302.605694 -250.601226)
		(end 301.864522 -250.601226)
		(width 0.18288)
		(layer "In11.Cu")
		(net "M_D_CPU0_SB_CA<3>")
	)
	(segment
		(start 312.863738 -247.514618)
		(end 312.670698 -247.707658)
		(width 0.18288)
		(layer "In11.Cu")
		(net "M_D_CPU0_SB_CA<3>")
	)
	(segment
		(start 279.062434 -250.629928)
		(end 278.869394 -250.436888)
		(width 0.18288)
		(layer "In11.Cu")
		(net "M_D_CPU0_SB_CA<3>")
	)
	(segment
		(start 334.407764 -249.12193)
		(end 334.393032 -249.130566)
		(width 0.088646)
		(layer "In11.Cu")
		(net "M_D_CPU0_SB_CA<3>")
	)
	(segment
		(start 286.546036 -250.408186)
		(end 286.546036 -250.171458)
		(width 0.18288)
		(layer "In11.Cu")
		(net "M_D_CPU0_SB_CA<3>")
	)
	(segment
		(start 282.23337 -250.413266)
		(end 282.04033 -250.220226)
		(width 0.18288)
		(layer "In11.Cu")
		(net "M_D_CPU0_SB_CA<3>")
	)
	(segment
		(start 343.981024 -248.371868)
		(end 343.876122 -248.3104)
		(width 0.088646)
		(layer "In11.Cu")
		(net "M_D_CPU0_SB_CA<3>")
	)
	(segment
		(start 300.777402 -250.601226)
		(end 300.073568 -250.601226)
		(width 0.18288)
		(layer "In11.Cu")
		(net "M_D_CPU0_SB_CA<3>")
	)
	(segment
		(start 297.332908 -250.25604)
		(end 296.085006 -250.25604)
		(width 0.18288)
		(layer "In11.Cu")
		(net "M_D_CPU0_SB_CA<3>")
	)
	(segment
		(start 288.534094 -250.194826)
		(end 288.127694 -250.601226)
		(width 0.18288)
		(layer "In11.Cu")
		(net "M_D_CPU0_SB_CA<3>")
	)
	(segment
		(start 293.090346 -250.601226)
		(end 292.351714 -250.601226)
		(width 0.18288)
		(layer "In11.Cu")
		(net "M_D_CPU0_SB_CA<3>")
	)
	(segment
		(start 315.496956 -249.110246)
		(end 314.487052 -248.100342)
		(width 0.18288)
		(layer "In11.Cu")
		(net "M_D_CPU0_SB_CA<3>")
	)
	(segment
		(start 339.106764 -249.12193)
		(end 339.092032 -249.130566)
		(width 0.088646)
		(layer "In11.Cu")
		(net "M_D_CPU0_SB_CA<3>")
	)
	(segment
		(start 279.403556 -250.629928)
		(end 279.062434 -250.629928)
		(width 0.18288)
		(layer "In11.Cu")
		(net "M_D_CPU0_SB_CA<3>")
	)
	(segment
		(start 340.986364 -249.12193)
		(end 340.971632 -249.130566)
		(width 0.088646)
		(layer "In11.Cu")
		(net "M_D_CPU0_SB_CA<3>")
	)
	(segment
		(start 289.770566 -250.194826)
		(end 288.534094 -250.194826)
		(width 0.18288)
		(layer "In11.Cu")
		(net "M_D_CPU0_SB_CA<3>")
	)
	(segment
		(start 282.74137 -250.767596)
		(end 282.42641 -250.767596)
		(width 0.18288)
		(layer "In11.Cu")
		(net "M_D_CPU0_SB_CA<3>")
	)
	(segment
		(start 313.371738 -247.907302)
		(end 313.371738 -247.707658)
		(width 0.18288)
		(layer "In11.Cu")
		(net "M_D_CPU0_SB_CA<3>")
	)
	(segment
		(start 328.933302 -249.065542)
		(end 327.868026 -248.000266)
		(width 0.18288)
		(layer "In11.Cu")
		(net "M_D_CPU0_SB_CA<3>")
	)
	(segment
		(start 295.900094 -250.440952)
		(end 294.9575 -250.440952)
		(width 0.18288)
		(layer "In11.Cu")
		(net "M_D_CPU0_SB_CA<3>")
	)
	(segment
		(start 296.085006 -250.25604)
		(end 295.900094 -250.440952)
		(width 0.18288)
		(layer "In11.Cu")
		(net "M_D_CPU0_SB_CA<3>")
	)
	(segment
		(start 285.844996 -250.408186)
		(end 285.651956 -250.601226)
		(width 0.18288)
		(layer "In11.Cu")
		(net "M_D_CPU0_SB_CA<3>")
	)
	(segment
		(start 278.676354 -250.11253)
		(end 278.361394 -250.11253)
		(width 0.18288)
		(layer "In11.Cu")
		(net "M_D_CPU0_SB_CA<3>")
	)
	(segment
		(start 311.172098 -248.100342)
		(end 310.373014 -248.899426)
		(width 0.18288)
		(layer "In11.Cu")
		(net "M_D_CPU0_SB_CA<3>")
	)
	(segment
		(start 283.713428 -250.441206)
		(end 283.492448 -250.220226)
		(width 0.18288)
		(layer "In11.Cu")
		(net "M_D_CPU0_SB_CA<3>")
	)
	(segment
		(start 299.913294 -250.440952)
		(end 297.51782 -250.440952)
		(width 0.18288)
		(layer "In11.Cu")
		(net "M_D_CPU0_SB_CA<3>")
	)
	(segment
		(start 301.163482 -249.969528)
		(end 300.970442 -250.162568)
		(width 0.18288)
		(layer "In11.Cu")
		(net "M_D_CPU0_SB_CA<3>")
	)
	(segment
		(start 274.195794 -250.245626)
		(end 273.344894 -250.245626)
		(width 0.18288)
		(layer "In11.Cu")
		(net "M_D_CPU0_SB_CA<3>")
	)
	(segment
		(start 313.178698 -247.514618)
		(end 312.863738 -247.514618)
		(width 0.18288)
		(layer "In11.Cu")
		(net "M_D_CPU0_SB_CA<3>")
	)
	(segment
		(start 294.957246 -250.441206)
		(end 294.275764 -250.441206)
		(width 0.18288)
		(layer "In11.Cu")
		(net "M_D_CPU0_SB_CA<3>")
	)
	(segment
		(start 282.42641 -250.767596)
		(end 282.23337 -250.574556)
		(width 0.18288)
		(layer "In11.Cu")
		(net "M_D_CPU0_SB_CA<3>")
	)
	(segment
		(start 312.477658 -248.100342)
		(end 311.172098 -248.100342)
		(width 0.18288)
		(layer "In11.Cu")
		(net "M_D_CPU0_SB_CA<3>")
	)
	(segment
		(start 286.739076 -250.601226)
		(end 286.546036 -250.408186)
		(width 0.18288)
		(layer "In11.Cu")
		(net "M_D_CPU0_SB_CA<3>")
	)
	(segment
		(start 278.168354 -250.436888)
		(end 277.975314 -250.629928)
		(width 0.18288)
		(layer "In11.Cu")
		(net "M_D_CPU0_SB_CA<3>")
	)
	(segment
		(start 301.671482 -250.162568)
		(end 301.478442 -249.969528)
		(width 0.18288)
		(layer "In11.Cu")
		(net "M_D_CPU0_SB_CA<3>")
	)
	(segment
		(start 290.156646 -250.832874)
		(end 289.963606 -250.639834)
		(width 0.18288)
		(layer "In11.Cu")
		(net "M_D_CPU0_SB_CA<3>")
	)
	(segment
		(start 282.23337 -250.574556)
		(end 282.23337 -250.413266)
		(width 0.18288)
		(layer "In11.Cu")
		(net "M_D_CPU0_SB_CA<3>")
	)
	(segment
		(start 322.398644 -249.110246)
		(end 315.496956 -249.110246)
		(width 0.18288)
		(layer "In11.Cu")
		(net "M_D_CPU0_SB_CA<3>")
	)
	(segment
		(start 286.038036 -249.978418)
		(end 285.844996 -250.171458)
		(width 0.18288)
		(layer "In11.Cu")
		(net "M_D_CPU0_SB_CA<3>")
	)
	(segment
		(start 290.857686 -250.194826)
		(end 290.664646 -250.387866)
		(width 0.18288)
		(layer "In11.Cu")
		(net "M_D_CPU0_SB_CA<3>")
	)
	(segment
		(start 284.757114 -250.601226)
		(end 284.597094 -250.441206)
		(width 0.18288)
		(layer "In11.Cu")
		(net "M_D_CPU0_SB_CA<3>")
	)
	(segment
		(start 290.664646 -250.387866)
		(end 290.664646 -250.639834)
		(width 0.18288)
		(layer "In11.Cu")
		(net "M_D_CPU0_SB_CA<3>")
	)
	(segment
		(start 305.94173 -249.806206)
		(end 305.648614 -250.099322)
		(width 0.18288)
		(layer "In11.Cu")
		(net "M_D_CPU0_SB_CA<3>")
	)
	(segment
		(start 278.361394 -250.11253)
		(end 278.168354 -250.30557)
		(width 0.18288)
		(layer "In11.Cu")
		(net "M_D_CPU0_SB_CA<3>")
	)
	(segment
		(start 282.93441 -250.574556)
		(end 282.74137 -250.767596)
		(width 0.18288)
		(layer "In11.Cu")
		(net "M_D_CPU0_SB_CA<3>")
	)
	(segment
		(start 270.844264 -250.36907)
		(end 270.651224 -250.56211)
		(width 0.18288)
		(layer "In11.Cu")
		(net "M_D_CPU0_SB_CA<3>")
	)
	(segment
		(start 274.635976 -250.685808)
		(end 274.195794 -250.245626)
		(width 0.18288)
		(layer "In11.Cu")
		(net "M_D_CPU0_SB_CA<3>")
	)
	(segment
		(start 323.508624 -248.000266)
		(end 322.398644 -249.110246)
		(width 0.18288)
		(layer "In11.Cu")
		(net "M_D_CPU0_SB_CA<3>")
	)
	(segment
		(start 279.592278 -250.441206)
		(end 279.403556 -250.629928)
		(width 0.18288)
		(layer "In11.Cu")
		(net "M_D_CPU0_SB_CA<3>")
	)
	(segment
		(start 286.352996 -249.978418)
		(end 286.038036 -249.978418)
		(width 0.18288)
		(layer "In11.Cu")
		(net "M_D_CPU0_SB_CA<3>")
	)
	(segment
		(start 304.978054 -249.806206)
		(end 303.400714 -249.806206)
		(width 0.18288)
		(layer "In11.Cu")
		(net "M_D_CPU0_SB_CA<3>")
	)
	(segment
		(start 285.651956 -250.601226)
		(end 284.757114 -250.601226)
		(width 0.18288)
		(layer "In11.Cu")
		(net "M_D_CPU0_SB_CA<3>")
	)
	(segment
		(start 305.648614 -250.099322)
		(end 305.27117 -250.099322)
		(width 0.18288)
		(layer "In11.Cu")
		(net "M_D_CPU0_SB_CA<3>")
	)
	(segment
		(start 313.371738 -247.707658)
		(end 313.178698 -247.514618)
		(width 0.18288)
		(layer "In11.Cu")
		(net "M_D_CPU0_SB_CA<3>")
	)
	(segment
		(start 283.12745 -250.220226)
		(end 282.93441 -250.413266)
		(width 0.18288)
		(layer "In11.Cu")
		(net "M_D_CPU0_SB_CA<3>")
	)
	(segment
		(start 292.351714 -250.601226)
		(end 291.945314 -250.194826)
		(width 0.18288)
		(layer "In11.Cu")
		(net "M_D_CPU0_SB_CA<3>")
	)
	(segment
		(start 307.408834 -249.460766)
		(end 307.063394 -249.806206)
		(width 0.18288)
		(layer "In11.Cu")
		(net "M_D_CPU0_SB_CA<3>")
	)
	(segment
		(start 271.037304 -250.034806)
		(end 270.844264 -250.227846)
		(width 0.18288)
		(layer "In11.Cu")
		(net "M_D_CPU0_SB_CA<3>")
	)
	(segment
		(start 294.275764 -250.441206)
		(end 293.791386 -249.956828)
		(width 0.18288)
		(layer "In11.Cu")
		(net "M_D_CPU0_SB_CA<3>")
	)
	(segment
		(start 301.671482 -250.408186)
		(end 301.671482 -250.162568)
		(width 0.18288)
		(layer "In11.Cu")
		(net "M_D_CPU0_SB_CA<3>")
	)
	(segment
		(start 271.545304 -250.227846)
		(end 271.352264 -250.034806)
		(width 0.18288)
		(layer "In11.Cu")
		(net "M_D_CPU0_SB_CA<3>")
	)
	(segment
		(start 289.963606 -250.639834)
		(end 289.963606 -250.387866)
		(width 0.18288)
		(layer "In11.Cu")
		(net "M_D_CPU0_SB_CA<3>")
	)
	(segment
		(start 312.670698 -247.707658)
		(end 312.670698 -247.907302)
		(width 0.18288)
		(layer "In11.Cu")
		(net "M_D_CPU0_SB_CA<3>")
	)
	(segment
		(start 335.347564 -249.12193)
		(end 335.332832 -249.130566)
		(width 0.088646)
		(layer "In11.Cu")
		(net "M_D_CPU0_SB_CA<3>")
	)
	(segment
		(start 333.467964 -249.12193)
		(end 333.453232 -249.130566)
		(width 0.088646)
		(layer "In11.Cu")
		(net "M_D_CPU0_SB_CA<3>")
	)
	(segment
		(start 271.545304 -250.36907)
		(end 271.545304 -250.227846)
		(width 0.18288)
		(layer "In11.Cu")
		(net "M_D_CPU0_SB_CA<3>")
	)
	(segment
		(start 277.975314 -250.629928)
		(end 277.242016 -250.629928)
		(width 0.18288)
		(layer "In11.Cu")
		(net "M_D_CPU0_SB_CA<3>")
	)
	(segment
		(start 343.03843 -248.791984)
		(end 343.03843 -248.806208)
		(width 0.088646)
		(layer "In11.Cu")
		(net "M_D_CPU0_SB_CA<3>")
	)
	(segment
		(start 314.487052 -248.100342)
		(end 313.564778 -248.100342)
		(width 0.18288)
		(layer "In11.Cu")
		(net "M_D_CPU0_SB_CA<3>")
	)
	(segment
		(start 301.864522 -250.601226)
		(end 301.671482 -250.408186)
		(width 0.18288)
		(layer "In11.Cu")
		(net "M_D_CPU0_SB_CA<3>")
	)
	(segment
		(start 276.106128 -250.367546)
		(end 275.787866 -250.685808)
		(width 0.18288)
		(layer "In11.Cu")
		(net "M_D_CPU0_SB_CA<3>")
	)
	(segment
		(start 271.738344 -250.56211)
		(end 271.545304 -250.36907)
		(width 0.18288)
		(layer "In11.Cu")
		(net "M_D_CPU0_SB_CA<3>")
	)
	(segment
		(start 276.979634 -250.367546)
		(end 276.106128 -250.367546)
		(width 0.18288)
		(layer "In11.Cu")
		(net "M_D_CPU0_SB_CA<3>")
	)
	(segment
		(start 294.9575 -250.440952)
		(end 294.957246 -250.441206)
		(width 0.18288)
		(layer "In11.Cu")
		(net "M_D_CPU0_SB_CA<3>")
	)
	(segment
		(start 340.046564 -249.12193)
		(end 340.031832 -249.130566)
		(width 0.088646)
		(layer "In11.Cu")
		(net "M_D_CPU0_SB_CA<3>")
	)
	(segment
		(start 269.37462 -250.56211)
		(end 268.829282 -250.016772)
		(width 0.18288)
		(layer "In11.Cu")
		(net "M_D_CPU0_SB_CA<3>")
	)
	(segment
		(start 291.945314 -250.194826)
		(end 290.857686 -250.194826)
		(width 0.18288)
		(layer "In11.Cu")
		(net "M_D_CPU0_SB_CA<3>")
	)
	(segment
		(start 288.127694 -250.601226)
		(end 286.739076 -250.601226)
		(width 0.18288)
		(layer "In11.Cu")
		(net "M_D_CPU0_SB_CA<3>")
	)
	(segment
		(start 273.02841 -250.56211)
		(end 271.738344 -250.56211)
		(width 0.18288)
		(layer "In11.Cu")
		(net "M_D_CPU0_SB_CA<3>")
	)
	(segment
		(start 293.283386 -250.408186)
		(end 293.090346 -250.601226)
		(width 0.18288)
		(layer "In11.Cu")
		(net "M_D_CPU0_SB_CA<3>")
	)
	(segment
		(start 278.168354 -250.30557)
		(end 278.168354 -250.436888)
		(width 0.18288)
		(layer "In11.Cu")
		(net "M_D_CPU0_SB_CA<3>")
	)
	(segment
		(start 336.287364 -249.12193)
		(end 336.272632 -249.130566)
		(width 0.088646)
		(layer "In11.Cu")
		(net "M_D_CPU0_SB_CA<3>")
	)
	(segment
		(start 332.679802 -249.065542)
		(end 328.933302 -249.065542)
		(width 0.18288)
		(layer "In11.Cu")
		(net "M_D_CPU0_SB_CA<3>")
	)
	(segment
		(start 282.93441 -250.413266)
		(end 282.93441 -250.574556)
		(width 0.18288)
		(layer "In11.Cu")
		(net "M_D_CPU0_SB_CA<3>")
	)
	(segment
		(start 293.283386 -250.149868)
		(end 293.283386 -250.408186)
		(width 0.18288)
		(layer "In11.Cu")
		(net "M_D_CPU0_SB_CA<3>")
	)
	(segment
		(start 332.99908 -249.181112)
		(end 332.88351 -249.065542)
		(width 0.088646)
		(layer "In11.Cu")
		(net "M_D_CPU0_SB_CA<3>")
	)
	(segment
		(start 341.921846 -249.12447)
		(end 341.911432 -249.130566)
		(width 0.088646)
		(layer "In11.Cu")
		(net "M_D_CPU0_SB_CA<3>")
	)
	(segment
		(start 305.27117 -250.099322)
		(end 304.978054 -249.806206)
		(width 0.18288)
		(layer "In11.Cu")
		(net "M_D_CPU0_SB_CA<3>")
	)
	(segment
		(start 278.869394 -250.436888)
		(end 278.869394 -250.30557)
		(width 0.18288)
		(layer "In11.Cu")
		(net "M_D_CPU0_SB_CA<3>")
	)
	(segment
		(start 307.063394 -249.806206)
		(end 305.94173 -249.806206)
		(width 0.18288)
		(layer "In11.Cu")
		(net "M_D_CPU0_SB_CA<3>")
	)
	(segment
		(start 289.963606 -250.387866)
		(end 289.770566 -250.194826)
		(width 0.18288)
		(layer "In11.Cu")
		(net "M_D_CPU0_SB_CA<3>")
	)
	(segment
		(start 290.664646 -250.639834)
		(end 290.471606 -250.832874)
		(width 0.18288)
		(layer "In11.Cu")
		(net "M_D_CPU0_SB_CA<3>")
	)
	(segment
		(start 275.787866 -250.685808)
		(end 274.635976 -250.685808)
		(width 0.18288)
		(layer "In11.Cu")
		(net "M_D_CPU0_SB_CA<3>")
	)
	(segment
		(start 303.400714 -249.806206)
		(end 302.605694 -250.601226)
		(width 0.18288)
		(layer "In11.Cu")
		(net "M_D_CPU0_SB_CA<3>")
	)
	(segment
		(start 300.970442 -250.408186)
		(end 300.777402 -250.601226)
		(width 0.18288)
		(layer "In11.Cu")
		(net "M_D_CPU0_SB_CA<3>")
	)
	(segment
		(start 333.266034 -249.181112)
		(end 332.99908 -249.181112)
		(width 0.088646)
		(layer "In11.Cu")
		(net "M_D_CPU0_SB_CA<3>")
	)
	(segment
		(start 293.791386 -249.956828)
		(end 293.476426 -249.956828)
		(width 0.18288)
		(layer "In11.Cu")
		(net "M_D_CPU0_SB_CA<3>")
	)
	(segment
		(start 285.844996 -250.171458)
		(end 285.844996 -250.408186)
		(width 0.18288)
		(layer "In11.Cu")
		(net "M_D_CPU0_SB_CA<3>")
	)
	(segment
		(start 283.492448 -250.220226)
		(end 283.12745 -250.220226)
		(width 0.18288)
		(layer "In11.Cu")
		(net "M_D_CPU0_SB_CA<3>")
	)
	(segment
		(start 337.227164 -249.12193)
		(end 337.212432 -249.130566)
		(width 0.088646)
		(layer "In11.Cu")
		(net "M_D_CPU0_SB_CA<3>")
	)
	(segment
		(start 327.868026 -248.000266)
		(end 323.508624 -248.000266)
		(width 0.18288)
		(layer "In11.Cu")
		(net "M_D_CPU0_SB_CA<3>")
	)
	(segment
		(start 280.19756 -250.441206)
		(end 279.592278 -250.441206)
		(width 0.18288)
		(layer "In11.Cu")
		(net "M_D_CPU0_SB_CA<3>")
	)
	(segment
		(start 300.073568 -250.601226)
		(end 299.913294 -250.440952)
		(width 0.18288)
		(layer "In11.Cu")
		(net "M_D_CPU0_SB_CA<3>")
	)
	(segment
		(start 280.41854 -250.220226)
		(end 280.19756 -250.441206)
		(width 0.18288)
		(layer "In11.Cu")
		(net "M_D_CPU0_SB_CA<3>")
	)
	(segment
		(start 286.546036 -250.171458)
		(end 286.352996 -249.978418)
		(width 0.18288)
		(layer "In11.Cu")
		(net "M_D_CPU0_SB_CA<3>")
	)
	(segment
		(start 278.869394 -250.30557)
		(end 278.676354 -250.11253)
		(width 0.18288)
		(layer "In11.Cu")
		(net "M_D_CPU0_SB_CA<3>")
	)
	(segment
		(start 282.04033 -250.220226)
		(end 280.41854 -250.220226)
		(width 0.18288)
		(layer "In11.Cu")
		(net "M_D_CPU0_SB_CA<3>")
	)
	(segment
		(start 308.625494 -249.460766)
		(end 307.408834 -249.460766)
		(width 0.18288)
		(layer "In11.Cu")
		(net "M_D_CPU0_SB_CA<3>")
	)
	(segment
		(start 310.373014 -248.899426)
		(end 309.186834 -248.899426)
		(width 0.18288)
		(layer "In11.Cu")
		(net "M_D_CPU0_SB_CA<3>")
	)
	(segment
		(start 313.564778 -248.100342)
		(end 313.371738 -247.907302)
		(width 0.18288)
		(layer "In11.Cu")
		(net "M_D_CPU0_SB_CA<3>")
	)
	(segment
		(start 332.88351 -249.065542)
		(end 332.679802 -249.065542)
		(width 0.088646)
		(layer "In11.Cu")
		(net "M_D_CPU0_SB_CA<3>")
	)
	(segment
		(start 300.970442 -250.162568)
		(end 300.970442 -250.408186)
		(width 0.18288)
		(layer "In11.Cu")
		(net "M_D_CPU0_SB_CA<3>")
	)
	(segment
		(start 290.471606 -250.832874)
		(end 290.156646 -250.832874)
		(width 0.18288)
		(layer "In11.Cu")
		(net "M_D_CPU0_SB_CA<3>")
	)
	(segment
		(start 271.352264 -250.034806)
		(end 271.037304 -250.034806)
		(width 0.18288)
		(layer "In11.Cu")
		(net "M_D_CPU0_SB_CA<3>")
	)
	(segment
		(start 273.344894 -250.245626)
		(end 273.02841 -250.56211)
		(width 0.18288)
		(layer "In11.Cu")
		(net "M_D_CPU0_SB_CA<3>")
	)
	(segment
		(start 342.859868 -249.125486)
		(end 342.850978 -249.130566)
		(width 0.088646)
		(layer "In11.Cu")
		(net "M_D_CPU0_SB_CA<3>")
	)
	(segment
		(start 297.51782 -250.440952)
		(end 297.332908 -250.25604)
		(width 0.18288)
		(layer "In11.Cu")
		(net "M_D_CPU0_SB_CA<3>")
	)
	(segment
		(start 277.242016 -250.629928)
		(end 276.979634 -250.367546)
		(width 0.18288)
		(layer "In11.Cu")
		(net "M_D_CPU0_SB_CA<3>")
	)
	(segment
		(start 293.476426 -249.956828)
		(end 293.283386 -250.149868)
		(width 0.18288)
		(layer "In11.Cu")
		(net "M_D_CPU0_SB_CA<3>")
	)
	(segment
		(start 270.651224 -250.56211)
		(end 269.37462 -250.56211)
		(width 0.18288)
		(layer "In11.Cu")
		(net "M_D_CPU0_SB_CA<3>")
	)
	(segment
		(start 312.670698 -247.907302)
		(end 312.477658 -248.100342)
		(width 0.18288)
		(layer "In11.Cu")
		(net "M_D_CPU0_SB_CA<3>")
	)
	(segment
		(start 301.478442 -249.969528)
		(end 301.163482 -249.969528)
		(width 0.18288)
		(layer "In11.Cu")
		(net "M_D_CPU0_SB_CA<3>")
	)
	(segment
		(start 309.186834 -248.899426)
		(end 308.625494 -249.460766)
		(width 0.18288)
		(layer "In11.Cu")
		(net "M_D_CPU0_SB_CA<3>")
	)
	(segment
		(start 284.597094 -250.441206)
		(end 283.713428 -250.441206)
		(width 0.18288)
		(layer "In11.Cu")
		(net "M_D_CPU0_SB_CA<3>")
	)
	(arc
		(start 335.898236 -249.130566)
		(mid 335.624037 -249.054731)
		(end 335.347564 -249.12193)
		(width 0.088646)
		(layer "In11.Cu")
		(net "M_D_CPU0_SB_CA<3>")
	)
	(arc
		(start 341.911432 -249.130566)
		(mid 341.724234 -249.180709)
		(end 341.537036 -249.130566)
		(width 0.088646)
		(layer "In11.Cu")
		(net "M_D_CPU0_SB_CA<3>")
	)
	(arc
		(start 336.838036 -249.130566)
		(mid 336.563837 -249.054731)
		(end 336.287364 -249.12193)
		(width 0.088646)
		(layer "In11.Cu")
		(net "M_D_CPU0_SB_CA<3>")
	)
	(arc
		(start 339.657436 -249.130566)
		(mid 339.383237 -249.054731)
		(end 339.106764 -249.12193)
		(width 0.088646)
		(layer "In11.Cu")
		(net "M_D_CPU0_SB_CA<3>")
	)
	(arc
		(start 338.717636 -249.130566)
		(mid 338.434934 -249.05479)
		(end 338.152232 -249.130566)
		(width 0.088646)
		(layer "In11.Cu")
		(net "M_D_CPU0_SB_CA<3>")
	)
	(arc
		(start 344.543634 -248.806208)
		(mid 344.276237 -248.571023)
		(end 343.981024 -248.371868)
		(width 0.088646)
		(layer "In11.Cu")
		(net "M_D_CPU0_SB_CA<3>")
	)
	(arc
		(start 336.272632 -249.130566)
		(mid 336.085434 -249.180709)
		(end 335.898236 -249.130566)
		(width 0.088646)
		(layer "In11.Cu")
		(net "M_D_CPU0_SB_CA<3>")
	)
	(arc
		(start 333.453232 -249.130566)
		(mid 333.36296 -249.168165)
		(end 333.266034 -249.181112)
		(width 0.088646)
		(layer "In11.Cu")
		(net "M_D_CPU0_SB_CA<3>")
	)
	(arc
		(start 342.850978 -249.130566)
		(mid 342.66378 -249.180709)
		(end 342.476582 -249.130566)
		(width 0.088646)
		(layer "In11.Cu")
		(net "M_D_CPU0_SB_CA<3>")
	)
	(arc
		(start 341.537036 -249.130566)
		(mid 341.262837 -249.054731)
		(end 340.986364 -249.12193)
		(width 0.088646)
		(layer "In11.Cu")
		(net "M_D_CPU0_SB_CA<3>")
	)
	(arc
		(start 334.958436 -249.130566)
		(mid 334.684237 -249.054731)
		(end 334.407764 -249.12193)
		(width 0.088646)
		(layer "In11.Cu")
		(net "M_D_CPU0_SB_CA<3>")
	)
	(arc
		(start 337.777836 -249.130566)
		(mid 337.503637 -249.054731)
		(end 337.227164 -249.12193)
		(width 0.088646)
		(layer "In11.Cu")
		(net "M_D_CPU0_SB_CA<3>")
	)
	(arc
		(start 334.018636 -249.130566)
		(mid 333.744437 -249.054731)
		(end 333.467964 -249.12193)
		(width 0.088646)
		(layer "In11.Cu")
		(net "M_D_CPU0_SB_CA<3>")
	)
	(arc
		(start 334.393032 -249.130566)
		(mid 334.205834 -249.180709)
		(end 334.018636 -249.130566)
		(width 0.088646)
		(layer "In11.Cu")
		(net "M_D_CPU0_SB_CA<3>")
	)
	(arc
		(start 343.03843 -248.806208)
		(mid 342.990751 -248.989108)
		(end 342.859868 -249.125486)
		(width 0.088646)
		(layer "In11.Cu")
		(net "M_D_CPU0_SB_CA<3>")
	)
	(arc
		(start 340.597236 -249.130566)
		(mid 340.323037 -249.054731)
		(end 340.046564 -249.12193)
		(width 0.088646)
		(layer "In11.Cu")
		(net "M_D_CPU0_SB_CA<3>")
	)
	(arc
		(start 338.152232 -249.130566)
		(mid 337.965034 -249.180709)
		(end 337.777836 -249.130566)
		(width 0.088646)
		(layer "In11.Cu")
		(net "M_D_CPU0_SB_CA<3>")
	)
	(arc
		(start 337.212432 -249.130566)
		(mid 337.025234 -249.180709)
		(end 336.838036 -249.130566)
		(width 0.088646)
		(layer "In11.Cu")
		(net "M_D_CPU0_SB_CA<3>")
	)
	(arc
		(start 340.971632 -249.130566)
		(mid 340.784434 -249.180709)
		(end 340.597236 -249.130566)
		(width 0.088646)
		(layer "In11.Cu")
		(net "M_D_CPU0_SB_CA<3>")
	)
	(arc
		(start 340.031832 -249.130566)
		(mid 339.844634 -249.180709)
		(end 339.657436 -249.130566)
		(width 0.088646)
		(layer "In11.Cu")
		(net "M_D_CPU0_SB_CA<3>")
	)
	(arc
		(start 335.332832 -249.130566)
		(mid 335.145634 -249.180709)
		(end 334.958436 -249.130566)
		(width 0.088646)
		(layer "In11.Cu")
		(net "M_D_CPU0_SB_CA<3>")
	)
	(arc
		(start 342.476582 -249.130566)
		(mid 342.200023 -249.054823)
		(end 341.921846 -249.12447)
		(width 0.088646)
		(layer "In11.Cu")
		(net "M_D_CPU0_SB_CA<3>")
	)
	(arc
		(start 339.092032 -249.130566)
		(mid 338.904834 -249.180709)
		(end 338.717636 -249.130566)
		(width 0.088646)
		(layer "In11.Cu")
		(net "M_D_CPU0_SB_CA<3>")
	)
	(arc
		(start 343.876122 -248.3104)
		(mid 343.321929 -248.315804)
		(end 343.03843 -248.791984)
		(width 0.088646)
		(layer "In11.Cu")
		(net "M_D_CPU0_SB_CA<3>")
	)
	(segment
		(start 261.984998 -250.866656)
		(end 261.560056 -250.441714)
		(width 0.20066)
		(layer "F.Cu")
		(net "M_D_CPU0_SB_CA<2>")
	)
	(segment
		(start 261.560056 -250.441714)
		(end 261.381494 -250.441714)
		(width 0.20066)
		(layer "F.Cu")
		(net "M_D_CPU0_SB_CA<2>")
	)
	(segment
		(start 261.050786 -250.441714)
		(end 259.065268 -250.441714)
		(width 0.1016)
		(layer "F.Cu")
		(net "M_D_CPU0_SB_CA<2>")
	)
	(segment
		(start 258.28498 -250.923552)
		(end 258.130548 -251.077984)
		(width 0.20066)
		(layer "F.Cu")
		(net "M_D_CPU0_SB_CA<2>")
	)
	(segment
		(start 259.056378 -250.432824)
		(end 258.44754 -250.432824)
		(width 0.20066)
		(layer "F.Cu")
		(net "M_D_CPU0_SB_CA<2>")
	)
	(segment
		(start 257.414776 -250.866656)
		(end 256.080514 -250.866656)
		(width 0.20066)
		(layer "F.Cu")
		(net "M_D_CPU0_SB_CA<2>")
	)
	(segment
		(start 343.60358 -249.342148)
		(end 343.603834 -249.341894)
		(width 0.20066)
		(layer "F.Cu")
		(net "M_D_CPU0_SB_CA<2>")
	)
	(segment
		(start 259.065268 -250.441714)
		(end 259.056378 -250.432824)
		(width 0.1016)
		(layer "F.Cu")
		(net "M_D_CPU0_SB_CA<2>")
	)
	(segment
		(start 264.729214 -250.866656)
		(end 263.624314 -250.866656)
		(width 0.20066)
		(layer "F.Cu")
		(net "M_D_CPU0_SB_CA<2>")
	)
	(segment
		(start 343.603834 -249.341894)
		(end 343.603834 -248.806208)
		(width 0.20066)
		(layer "F.Cu")
		(net "M_D_CPU0_SB_CA<2>")
	)
	(segment
		(start 258.130548 -251.077984)
		(end 257.626104 -251.077984)
		(width 0.20066)
		(layer "F.Cu")
		(net "M_D_CPU0_SB_CA<2>")
	)
	(segment
		(start 258.28498 -250.595384)
		(end 258.28498 -250.923552)
		(width 0.20066)
		(layer "F.Cu")
		(net "M_D_CPU0_SB_CA<2>")
	)
	(segment
		(start 261.381494 -250.441714)
		(end 261.050786 -250.441714)
		(width 0.101854)
		(layer "F.Cu")
		(net "M_D_CPU0_SB_CA<2>")
	)
	(segment
		(start 263.624314 -250.866656)
		(end 261.984998 -250.866656)
		(width 0.20066)
		(layer "F.Cu")
		(net "M_D_CPU0_SB_CA<2>")
	)
	(segment
		(start 257.626104 -251.077984)
		(end 257.414776 -250.866656)
		(width 0.20066)
		(layer "F.Cu")
		(net "M_D_CPU0_SB_CA<2>")
	)
	(segment
		(start 258.44754 -250.432824)
		(end 258.28498 -250.595384)
		(width 0.20066)
		(layer "F.Cu")
		(net "M_D_CPU0_SB_CA<2>")
	)
	(segment
		(start 343.02573 -249.249946)
		(end 342.946482 -249.295666)
		(width 0.088646)
		(layer "In11.Cu")
		(net "M_D_CPU0_SB_CA<2>")
	)
	(segment
		(start 342.006682 -249.295666)
		(end 341.99195 -249.304302)
		(width 0.088646)
		(layer "In11.Cu")
		(net "M_D_CPU0_SB_CA<2>")
	)
	(segment
		(start 301.555658 -251.947426)
		(end 301.240698 -251.947426)
		(width 0.18288)
		(layer "In11.Cu")
		(net "M_D_CPU0_SB_CA<2>")
	)
	(segment
		(start 286.612838 -251.302266)
		(end 286.612838 -251.6632)
		(width 0.18288)
		(layer "In11.Cu")
		(net "M_D_CPU0_SB_CA<2>")
	)
	(segment
		(start 299.862494 -251.29109)
		(end 297.31843 -251.29109)
		(width 0.18288)
		(layer "In11.Cu")
		(net "M_D_CPU0_SB_CA<2>")
	)
	(segment
		(start 282.18003 -251.29109)
		(end 282.006294 -251.464826)
		(width 0.18288)
		(layer "In11.Cu")
		(net "M_D_CPU0_SB_CA<2>")
	)
	(segment
		(start 266.665202 -251.3076)
		(end 266.350242 -251.3076)
		(width 0.18288)
		(layer "In11.Cu")
		(net "M_D_CPU0_SB_CA<2>")
	)
	(segment
		(start 286.612838 -251.6632)
		(end 286.419798 -251.85624)
		(width 0.18288)
		(layer "In11.Cu")
		(net "M_D_CPU0_SB_CA<2>")
	)
	(segment
		(start 295.976294 -251.29109)
		(end 293.440358 -251.29109)
		(width 0.18288)
		(layer "In11.Cu")
		(net "M_D_CPU0_SB_CA<2>")
	)
	(segment
		(start 338.247736 -249.295666)
		(end 338.237322 -249.301762)
		(width 0.088646)
		(layer "In11.Cu")
		(net "M_D_CPU0_SB_CA<2>")
	)
	(segment
		(start 334.488282 -249.295666)
		(end 334.47355 -249.304302)
		(width 0.088646)
		(layer "In11.Cu")
		(net "M_D_CPU0_SB_CA<2>")
	)
	(segment
		(start 337.307682 -249.295666)
		(end 337.29295 -249.304302)
		(width 0.088646)
		(layer "In11.Cu")
		(net "M_D_CPU0_SB_CA<2>")
	)
	(segment
		(start 267.559282 -251.845318)
		(end 267.366242 -252.038358)
		(width 0.18288)
		(layer "In11.Cu")
		(net "M_D_CPU0_SB_CA<2>")
	)
	(segment
		(start 269.865094 -251.160026)
		(end 269.734284 -251.290836)
		(width 0.18288)
		(layer "In11.Cu")
		(net "M_D_CPU0_SB_CA<2>")
	)
	(segment
		(start 301.240698 -251.947426)
		(end 301.047658 -251.754386)
		(width 0.18288)
		(layer "In11.Cu")
		(net "M_D_CPU0_SB_CA<2>")
	)
	(segment
		(start 266.858242 -251.50064)
		(end 266.665202 -251.3076)
		(width 0.18288)
		(layer "In11.Cu")
		(net "M_D_CPU0_SB_CA<2>")
	)
	(segment
		(start 341.066882 -249.295666)
		(end 341.05215 -249.304302)
		(width 0.088646)
		(layer "In11.Cu")
		(net "M_D_CPU0_SB_CA<2>")
	)
	(segment
		(start 301.047658 -251.754386)
		(end 301.047658 -251.302266)
		(width 0.18288)
		(layer "In11.Cu")
		(net "M_D_CPU0_SB_CA<2>")
	)
	(segment
		(start 269.734284 -251.290836)
		(end 267.752322 -251.290836)
		(width 0.18288)
		(layer "In11.Cu")
		(net "M_D_CPU0_SB_CA<2>")
	)
	(segment
		(start 297.31843 -251.29109)
		(end 297.017694 -251.591826)
		(width 0.18288)
		(layer "In11.Cu")
		(net "M_D_CPU0_SB_CA<2>")
	)
	(segment
		(start 293.258494 -251.109226)
		(end 292.271958 -251.109226)
		(width 0.18288)
		(layer "In11.Cu")
		(net "M_D_CPU0_SB_CA<2>")
	)
	(segment
		(start 277.14829 -251.170694)
		(end 276.904958 -251.414026)
		(width 0.18288)
		(layer "In11.Cu")
		(net "M_D_CPU0_SB_CA<2>")
	)
	(segment
		(start 266.350242 -251.3076)
		(end 266.157202 -251.50064)
		(width 0.18288)
		(layer "In11.Cu")
		(net "M_D_CPU0_SB_CA<2>")
	)
	(segment
		(start 276.904958 -251.414026)
		(end 273.598894 -251.414026)
		(width 0.18288)
		(layer "In11.Cu")
		(net "M_D_CPU0_SB_CA<2>")
	)
	(segment
		(start 282.006294 -251.464826)
		(end 281.444954 -251.464826)
		(width 0.18288)
		(layer "In11.Cu")
		(net "M_D_CPU0_SB_CA<2>")
	)
	(segment
		(start 307.040534 -250.370086)
		(end 306.300124 -250.370086)
		(width 0.18288)
		(layer "In11.Cu")
		(net "M_D_CPU0_SB_CA<2>")
	)
	(segment
		(start 278.124158 -251.29109)
		(end 278.003762 -251.170694)
		(width 0.18288)
		(layer "In11.Cu")
		(net "M_D_CPU0_SB_CA<2>")
	)
	(segment
		(start 301.047658 -251.302266)
		(end 300.854618 -251.109226)
		(width 0.18288)
		(layer "In11.Cu")
		(net "M_D_CPU0_SB_CA<2>")
	)
	(segment
		(start 265.456162 -251.845318)
		(end 265.456162 -251.483876)
		(width 0.18288)
		(layer "In11.Cu")
		(net "M_D_CPU0_SB_CA<2>")
	)
	(segment
		(start 265.649202 -252.038358)
		(end 265.456162 -251.845318)
		(width 0.18288)
		(layer "In11.Cu")
		(net "M_D_CPU0_SB_CA<2>")
	)
	(segment
		(start 285.718758 -251.109226)
		(end 284.626558 -251.109226)
		(width 0.18288)
		(layer "In11.Cu")
		(net "M_D_CPU0_SB_CA<2>")
	)
	(segment
		(start 333.174848 -249.371358)
		(end 333.112872 -249.433334)
		(width 0.088646)
		(layer "In11.Cu")
		(net "M_D_CPU0_SB_CA<2>")
	)
	(segment
		(start 301.941738 -251.109226)
		(end 301.748698 -251.302266)
		(width 0.18288)
		(layer "In11.Cu")
		(net "M_D_CPU0_SB_CA<2>")
	)
	(segment
		(start 284.444694 -251.29109)
		(end 282.18003 -251.29109)
		(width 0.18288)
		(layer "In11.Cu")
		(net "M_D_CPU0_SB_CA<2>")
	)
	(segment
		(start 286.104838 -251.85624)
		(end 285.911798 -251.6632)
		(width 0.18288)
		(layer "In11.Cu")
		(net "M_D_CPU0_SB_CA<2>")
	)
	(segment
		(start 265.456162 -251.483876)
		(end 265.263122 -251.290836)
		(width 0.18288)
		(layer "In11.Cu")
		(net "M_D_CPU0_SB_CA<2>")
	)
	(segment
		(start 333.112872 -249.433334)
		(end 332.679802 -249.433334)
		(width 0.088646)
		(layer "In11.Cu")
		(net "M_D_CPU0_SB_CA<2>")
	)
	(segment
		(start 309.608474 -249.470926)
		(end 308.531514 -250.547886)
		(width 0.18288)
		(layer "In11.Cu")
		(net "M_D_CPU0_SB_CA<2>")
	)
	(segment
		(start 265.964162 -252.038358)
		(end 265.649202 -252.038358)
		(width 0.18288)
		(layer "In11.Cu")
		(net "M_D_CPU0_SB_CA<2>")
	)
	(segment
		(start 265.263122 -251.290836)
		(end 265.153394 -251.290836)
		(width 0.18288)
		(layer "In11.Cu")
		(net "M_D_CPU0_SB_CA<2>")
	)
	(segment
		(start 336.367882 -249.295666)
		(end 336.35315 -249.304302)
		(width 0.088646)
		(layer "In11.Cu")
		(net "M_D_CPU0_SB_CA<2>")
	)
	(segment
		(start 322.608956 -249.618754)
		(end 315.273944 -249.618754)
		(width 0.18288)
		(layer "In11.Cu")
		(net "M_D_CPU0_SB_CA<2>")
	)
	(segment
		(start 328.812144 -249.433334)
		(end 327.724516 -248.345706)
		(width 0.18288)
		(layer "In11.Cu")
		(net "M_D_CPU0_SB_CA<2>")
	)
	(segment
		(start 266.858242 -251.845318)
		(end 266.858242 -251.50064)
		(width 0.18288)
		(layer "In11.Cu")
		(net "M_D_CPU0_SB_CA<2>")
	)
	(segment
		(start 292.271958 -251.109226)
		(end 292.037262 -251.343922)
		(width 0.18288)
		(layer "In11.Cu")
		(net "M_D_CPU0_SB_CA<2>")
	)
	(segment
		(start 306.040282 -250.629928)
		(end 304.86604 -250.629928)
		(width 0.18288)
		(layer "In11.Cu")
		(net "M_D_CPU0_SB_CA<2>")
	)
	(segment
		(start 304.86604 -250.629928)
		(end 304.606198 -250.370086)
		(width 0.18288)
		(layer "In11.Cu")
		(net "M_D_CPU0_SB_CA<2>")
	)
	(segment
		(start 303.751234 -250.370086)
		(end 303.012094 -251.109226)
		(width 0.18288)
		(layer "In11.Cu")
		(net "M_D_CPU0_SB_CA<2>")
	)
	(segment
		(start 311.501536 -248.639584)
		(end 310.670194 -249.470926)
		(width 0.18288)
		(layer "In11.Cu")
		(net "M_D_CPU0_SB_CA<2>")
	)
	(segment
		(start 288.87039 -251.343922)
		(end 288.635694 -251.109226)
		(width 0.18288)
		(layer "In11.Cu")
		(net "M_D_CPU0_SB_CA<2>")
	)
	(segment
		(start 340.127082 -249.295666)
		(end 340.11235 -249.304302)
		(width 0.088646)
		(layer "In11.Cu")
		(net "M_D_CPU0_SB_CA<2>")
	)
	(segment
		(start 296.27703 -251.591826)
		(end 295.976294 -251.29109)
		(width 0.18288)
		(layer "In11.Cu")
		(net "M_D_CPU0_SB_CA<2>")
	)
	(segment
		(start 314.294774 -248.639584)
		(end 311.501536 -248.639584)
		(width 0.18288)
		(layer "In11.Cu")
		(net "M_D_CPU0_SB_CA<2>")
	)
	(segment
		(start 288.635694 -251.109226)
		(end 286.805878 -251.109226)
		(width 0.18288)
		(layer "In11.Cu")
		(net "M_D_CPU0_SB_CA<2>")
	)
	(segment
		(start 286.419798 -251.85624)
		(end 286.104838 -251.85624)
		(width 0.18288)
		(layer "In11.Cu")
		(net "M_D_CPU0_SB_CA<2>")
	)
	(segment
		(start 304.606198 -250.370086)
		(end 303.751234 -250.370086)
		(width 0.18288)
		(layer "In11.Cu")
		(net "M_D_CPU0_SB_CA<2>")
	)
	(segment
		(start 315.273944 -249.618754)
		(end 314.294774 -248.639584)
		(width 0.18288)
		(layer "In11.Cu")
		(net "M_D_CPU0_SB_CA<2>")
	)
	(segment
		(start 297.017694 -251.591826)
		(end 296.27703 -251.591826)
		(width 0.18288)
		(layer "In11.Cu")
		(net "M_D_CPU0_SB_CA<2>")
	)
	(segment
		(start 308.531514 -250.547886)
		(end 307.218334 -250.547886)
		(width 0.18288)
		(layer "In11.Cu")
		(net "M_D_CPU0_SB_CA<2>")
	)
	(segment
		(start 265.153394 -251.290836)
		(end 264.729214 -250.866656)
		(width 0.18288)
		(layer "In11.Cu")
		(net "M_D_CPU0_SB_CA<2>")
	)
	(segment
		(start 306.300124 -250.370086)
		(end 306.040282 -250.629928)
		(width 0.18288)
		(layer "In11.Cu")
		(net "M_D_CPU0_SB_CA<2>")
	)
	(segment
		(start 273.344894 -251.160026)
		(end 269.865094 -251.160026)
		(width 0.18288)
		(layer "In11.Cu")
		(net "M_D_CPU0_SB_CA<2>")
	)
	(segment
		(start 332.679802 -249.433334)
		(end 328.812144 -249.433334)
		(width 0.18288)
		(layer "In11.Cu")
		(net "M_D_CPU0_SB_CA<2>")
	)
	(segment
		(start 286.805878 -251.109226)
		(end 286.612838 -251.302266)
		(width 0.18288)
		(layer "In11.Cu")
		(net "M_D_CPU0_SB_CA<2>")
	)
	(segment
		(start 267.559282 -251.483876)
		(end 267.559282 -251.845318)
		(width 0.18288)
		(layer "In11.Cu")
		(net "M_D_CPU0_SB_CA<2>")
	)
	(segment
		(start 310.670194 -249.470926)
		(end 309.608474 -249.470926)
		(width 0.18288)
		(layer "In11.Cu")
		(net "M_D_CPU0_SB_CA<2>")
	)
	(segment
		(start 339.187282 -249.295666)
		(end 339.176868 -249.301762)
		(width 0.088646)
		(layer "In11.Cu")
		(net "M_D_CPU0_SB_CA<2>")
	)
	(segment
		(start 285.911798 -251.6632)
		(end 285.911798 -251.302266)
		(width 0.18288)
		(layer "In11.Cu")
		(net "M_D_CPU0_SB_CA<2>")
	)
	(segment
		(start 266.157202 -251.845318)
		(end 265.964162 -252.038358)
		(width 0.18288)
		(layer "In11.Cu")
		(net "M_D_CPU0_SB_CA<2>")
	)
	(segment
		(start 323.882004 -248.345706)
		(end 322.608956 -249.618754)
		(width 0.18288)
		(layer "In11.Cu")
		(net "M_D_CPU0_SB_CA<2>")
	)
	(segment
		(start 327.724516 -248.345706)
		(end 323.882004 -248.345706)
		(width 0.18288)
		(layer "In11.Cu")
		(net "M_D_CPU0_SB_CA<2>")
	)
	(segment
		(start 278.003762 -251.170694)
		(end 277.14829 -251.170694)
		(width 0.18288)
		(layer "In11.Cu")
		(net "M_D_CPU0_SB_CA<2>")
	)
	(segment
		(start 266.157202 -251.50064)
		(end 266.157202 -251.845318)
		(width 0.18288)
		(layer "In11.Cu")
		(net "M_D_CPU0_SB_CA<2>")
	)
	(segment
		(start 267.752322 -251.290836)
		(end 267.559282 -251.483876)
		(width 0.18288)
		(layer "In11.Cu")
		(net "M_D_CPU0_SB_CA<2>")
	)
	(segment
		(start 273.598894 -251.414026)
		(end 273.344894 -251.160026)
		(width 0.18288)
		(layer "In11.Cu")
		(net "M_D_CPU0_SB_CA<2>")
	)
	(segment
		(start 285.911798 -251.302266)
		(end 285.718758 -251.109226)
		(width 0.18288)
		(layer "In11.Cu")
		(net "M_D_CPU0_SB_CA<2>")
	)
	(segment
		(start 307.218334 -250.547886)
		(end 307.040534 -250.370086)
		(width 0.18288)
		(layer "In11.Cu")
		(net "M_D_CPU0_SB_CA<2>")
	)
	(segment
		(start 335.428082 -249.295666)
		(end 335.41335 -249.304302)
		(width 0.088646)
		(layer "In11.Cu")
		(net "M_D_CPU0_SB_CA<2>")
	)
	(segment
		(start 300.854618 -251.109226)
		(end 300.044358 -251.109226)
		(width 0.18288)
		(layer "In11.Cu")
		(net "M_D_CPU0_SB_CA<2>")
	)
	(segment
		(start 267.366242 -252.038358)
		(end 267.051282 -252.038358)
		(width 0.18288)
		(layer "In11.Cu")
		(net "M_D_CPU0_SB_CA<2>")
	)
	(segment
		(start 293.440358 -251.29109)
		(end 293.258494 -251.109226)
		(width 0.18288)
		(layer "In11.Cu")
		(net "M_D_CPU0_SB_CA<2>")
	)
	(segment
		(start 292.037262 -251.343922)
		(end 288.87039 -251.343922)
		(width 0.18288)
		(layer "In11.Cu")
		(net "M_D_CPU0_SB_CA<2>")
	)
	(segment
		(start 303.012094 -251.109226)
		(end 301.941738 -251.109226)
		(width 0.18288)
		(layer "In11.Cu")
		(net "M_D_CPU0_SB_CA<2>")
	)
	(segment
		(start 301.748698 -251.302266)
		(end 301.748698 -251.754386)
		(width 0.18288)
		(layer "In11.Cu")
		(net "M_D_CPU0_SB_CA<2>")
	)
	(segment
		(start 301.748698 -251.754386)
		(end 301.555658 -251.947426)
		(width 0.18288)
		(layer "In11.Cu")
		(net "M_D_CPU0_SB_CA<2>")
	)
	(segment
		(start 300.044358 -251.109226)
		(end 299.862494 -251.29109)
		(width 0.18288)
		(layer "In11.Cu")
		(net "M_D_CPU0_SB_CA<2>")
	)
	(segment
		(start 267.051282 -252.038358)
		(end 266.858242 -251.845318)
		(width 0.18288)
		(layer "In11.Cu")
		(net "M_D_CPU0_SB_CA<2>")
	)
	(segment
		(start 281.271218 -251.29109)
		(end 278.124158 -251.29109)
		(width 0.18288)
		(layer "In11.Cu")
		(net "M_D_CPU0_SB_CA<2>")
	)
	(segment
		(start 333.266288 -249.371358)
		(end 333.174848 -249.371358)
		(width 0.088646)
		(layer "In11.Cu")
		(net "M_D_CPU0_SB_CA<2>")
	)
	(segment
		(start 281.444954 -251.464826)
		(end 281.271218 -251.29109)
		(width 0.18288)
		(layer "In11.Cu")
		(net "M_D_CPU0_SB_CA<2>")
	)
	(segment
		(start 284.626558 -251.109226)
		(end 284.444694 -251.29109)
		(width 0.18288)
		(layer "In11.Cu")
		(net "M_D_CPU0_SB_CA<2>")
	)
	(arc
		(start 341.441278 -249.295666)
		(mid 341.25408 -249.245523)
		(end 341.066882 -249.295666)
		(width 0.088646)
		(layer "In11.Cu")
		(net "M_D_CPU0_SB_CA<2>")
	)
	(arc
		(start 343.603834 -248.806208)
		(mid 343.329314 -249.04701)
		(end 343.02573 -249.249946)
		(width 0.088646)
		(layer "In11.Cu")
		(net "M_D_CPU0_SB_CA<2>")
	)
	(arc
		(start 333.30261 -249.370342)
		(mid 333.284457 -249.371145)
		(end 333.266288 -249.371358)
		(width 0.088646)
		(layer "In11.Cu")
		(net "M_D_CPU0_SB_CA<2>")
	)
	(arc
		(start 342.946482 -249.295666)
		(mid 342.66378 -249.371442)
		(end 342.381078 -249.295666)
		(width 0.088646)
		(layer "In11.Cu")
		(net "M_D_CPU0_SB_CA<2>")
	)
	(arc
		(start 336.35315 -249.304302)
		(mid 336.076675 -249.371622)
		(end 335.802478 -249.295666)
		(width 0.088646)
		(layer "In11.Cu")
		(net "M_D_CPU0_SB_CA<2>")
	)
	(arc
		(start 340.11235 -249.304302)
		(mid 339.835875 -249.371622)
		(end 339.561678 -249.295666)
		(width 0.088646)
		(layer "In11.Cu")
		(net "M_D_CPU0_SB_CA<2>")
	)
	(arc
		(start 333.922878 -249.295666)
		(mid 333.73568 -249.245523)
		(end 333.548482 -249.295666)
		(width 0.088646)
		(layer "In11.Cu")
		(net "M_D_CPU0_SB_CA<2>")
	)
	(arc
		(start 340.501478 -249.295666)
		(mid 340.31428 -249.245523)
		(end 340.127082 -249.295666)
		(width 0.088646)
		(layer "In11.Cu")
		(net "M_D_CPU0_SB_CA<2>")
	)
	(arc
		(start 338.622132 -249.295666)
		(mid 338.434934 -249.245523)
		(end 338.247736 -249.295666)
		(width 0.088646)
		(layer "In11.Cu")
		(net "M_D_CPU0_SB_CA<2>")
	)
	(arc
		(start 335.802478 -249.295666)
		(mid 335.61528 -249.245523)
		(end 335.428082 -249.295666)
		(width 0.088646)
		(layer "In11.Cu")
		(net "M_D_CPU0_SB_CA<2>")
	)
	(arc
		(start 334.47355 -249.304302)
		(mid 334.197075 -249.371622)
		(end 333.922878 -249.295666)
		(width 0.088646)
		(layer "In11.Cu")
		(net "M_D_CPU0_SB_CA<2>")
	)
	(arc
		(start 339.561678 -249.295666)
		(mid 339.37448 -249.245523)
		(end 339.187282 -249.295666)
		(width 0.088646)
		(layer "In11.Cu")
		(net "M_D_CPU0_SB_CA<2>")
	)
	(arc
		(start 341.05215 -249.304302)
		(mid 340.775675 -249.371622)
		(end 340.501478 -249.295666)
		(width 0.088646)
		(layer "In11.Cu")
		(net "M_D_CPU0_SB_CA<2>")
	)
	(arc
		(start 341.99195 -249.304302)
		(mid 341.715475 -249.371622)
		(end 341.441278 -249.295666)
		(width 0.088646)
		(layer "In11.Cu")
		(net "M_D_CPU0_SB_CA<2>")
	)
	(arc
		(start 335.41335 -249.304302)
		(mid 335.136875 -249.371622)
		(end 334.862678 -249.295666)
		(width 0.088646)
		(layer "In11.Cu")
		(net "M_D_CPU0_SB_CA<2>")
	)
	(arc
		(start 337.29295 -249.304302)
		(mid 337.016475 -249.371622)
		(end 336.742278 -249.295666)
		(width 0.088646)
		(layer "In11.Cu")
		(net "M_D_CPU0_SB_CA<2>")
	)
	(arc
		(start 342.381078 -249.295666)
		(mid 342.19388 -249.245523)
		(end 342.006682 -249.295666)
		(width 0.088646)
		(layer "In11.Cu")
		(net "M_D_CPU0_SB_CA<2>")
	)
	(arc
		(start 337.682078 -249.295666)
		(mid 337.49488 -249.245523)
		(end 337.307682 -249.295666)
		(width 0.088646)
		(layer "In11.Cu")
		(net "M_D_CPU0_SB_CA<2>")
	)
	(arc
		(start 334.862678 -249.295666)
		(mid 334.67548 -249.245523)
		(end 334.488282 -249.295666)
		(width 0.088646)
		(layer "In11.Cu")
		(net "M_D_CPU0_SB_CA<2>")
	)
	(arc
		(start 339.176868 -249.301762)
		(mid 338.89869 -249.371485)
		(end 338.622132 -249.295666)
		(width 0.088646)
		(layer "In11.Cu")
		(net "M_D_CPU0_SB_CA<2>")
	)
	(arc
		(start 338.237322 -249.301762)
		(mid 337.95889 -249.371608)
		(end 337.682078 -249.295666)
		(width 0.088646)
		(layer "In11.Cu")
		(net "M_D_CPU0_SB_CA<2>")
	)
	(arc
		(start 336.742278 -249.295666)
		(mid 336.55508 -249.245523)
		(end 336.367882 -249.295666)
		(width 0.088646)
		(layer "In11.Cu")
		(net "M_D_CPU0_SB_CA<2>")
	)
	(arc
		(start 333.548482 -249.295666)
		(mid 333.429851 -249.347186)
		(end 333.30261 -249.370342)
		(width 0.088646)
		(layer "In11.Cu")
		(net "M_D_CPU0_SB_CA<2>")
	)
	(segment
		(start 266.042394 -251.712476)
		(end 265.64717 -251.712476)
		(width 0.20066)
		(layer "F.Cu")
		(net "M_D_CPU0_SB_CA<1>")
	)
	(segment
		(start 266.25423 -251.924312)
		(end 266.042394 -251.712476)
		(width 0.20066)
		(layer "F.Cu")
		(net "M_D_CPU0_SB_CA<1>")
	)
	(segment
		(start 265.369548 -252.141736)
		(end 264.825226 -252.141736)
		(width 0.20066)
		(layer "F.Cu")
		(net "M_D_CPU0_SB_CA<1>")
	)
	(segment
		(start 267.724382 -251.716794)
		(end 266.90828 -251.716794)
		(width 0.20066)
		(layer "F.Cu")
		(net "M_D_CPU0_SB_CA<1>")
	)
	(segment
		(start 265.518646 -251.841)
		(end 265.518646 -251.992638)
		(width 0.20066)
		(layer "F.Cu")
		(net "M_D_CPU0_SB_CA<1>")
	)
	(segment
		(start 265.64717 -251.712476)
		(end 265.518646 -251.841)
		(width 0.20066)
		(layer "F.Cu")
		(net "M_D_CPU0_SB_CA<1>")
	)
	(segment
		(start 266.90828 -251.716794)
		(end 266.700762 -251.924312)
		(width 0.20066)
		(layer "F.Cu")
		(net "M_D_CPU0_SB_CA<1>")
	)
	(segment
		(start 268.829282 -251.716794)
		(end 267.724382 -251.716794)
		(width 0.20066)
		(layer "F.Cu")
		(net "M_D_CPU0_SB_CA<1>")
	)
	(segment
		(start 266.700762 -251.924312)
		(end 266.25423 -251.924312)
		(width 0.20066)
		(layer "F.Cu")
		(net "M_D_CPU0_SB_CA<1>")
	)
	(segment
		(start 262.752332 -252.141736)
		(end 262.514334 -252.141736)
		(width 0.101854)
		(layer "F.Cu")
		(net "M_D_CPU0_SB_CA<1>")
	)
	(segment
		(start 262.003794 -251.842778)
		(end 261.87781 -251.716794)
		(width 0.20066)
		(layer "F.Cu")
		(net "M_D_CPU0_SB_CA<1>")
	)
	(segment
		(start 262.50011 -252.15596)
		(end 262.146288 -252.15596)
		(width 0.20066)
		(layer "F.Cu")
		(net "M_D_CPU0_SB_CA<1>")
	)
	(segment
		(start 261.87781 -251.716794)
		(end 260.180582 -251.716794)
		(width 0.20066)
		(layer "F.Cu")
		(net "M_D_CPU0_SB_CA<1>")
	)
	(segment
		(start 262.003794 -252.013466)
		(end 262.003794 -251.842778)
		(width 0.20066)
		(layer "F.Cu")
		(net "M_D_CPU0_SB_CA<1>")
	)
	(segment
		(start 265.518646 -251.992638)
		(end 265.369548 -252.141736)
		(width 0.20066)
		(layer "F.Cu")
		(net "M_D_CPU0_SB_CA<1>")
	)
	(segment
		(start 264.825226 -252.141736)
		(end 262.752332 -252.141736)
		(width 0.1016)
		(layer "F.Cu")
		(net "M_D_CPU0_SB_CA<1>")
	)
	(segment
		(start 262.514334 -252.141736)
		(end 262.50011 -252.15596)
		(width 0.101854)
		(layer "F.Cu")
		(net "M_D_CPU0_SB_CA<1>")
	)
	(segment
		(start 262.146288 -252.15596)
		(end 262.003794 -252.013466)
		(width 0.20066)
		(layer "F.Cu")
		(net "M_D_CPU0_SB_CA<1>")
	)
	(segment
		(start 346.893134 -247.992138)
		(end 346.893134 -248.528078)
		(width 0.20066)
		(layer "F.Cu")
		(net "M_D_CPU0_SB_CA<1>")
	)
	(segment
		(start 290.36518 -252.407166)
		(end 289.989514 -252.0315)
		(width 0.18288)
		(layer "In11.Cu")
		(net "M_D_CPU0_SB_CA<1>")
	)
	(segment
		(start 345.670632 -249.130566)
		(end 345.664536 -249.134122)
		(width 0.088646)
		(layer "In11.Cu")
		(net "M_D_CPU0_SB_CA<1>")
	)
	(segment
		(start 328.805032 -249.929904)
		(end 327.566274 -248.691146)
		(width 0.18288)
		(layer "In11.Cu")
		(net "M_D_CPU0_SB_CA<1>")
	)
	(segment
		(start 291.292788 -252.0315)
		(end 290.917122 -252.407166)
		(width 0.18288)
		(layer "In11.Cu")
		(net "M_D_CPU0_SB_CA<1>")
	)
	(segment
		(start 336.17535 -249.929904)
		(end 328.805032 -249.929904)
		(width 0.18288)
		(layer "In11.Cu")
		(net "M_D_CPU0_SB_CA<1>")
	)
	(segment
		(start 327.566274 -248.691146)
		(end 324.255384 -248.691146)
		(width 0.18288)
		(layer "In11.Cu")
		(net "M_D_CPU0_SB_CA<1>")
	)
	(segment
		(start 297.725846 -252.140974)
		(end 297.411394 -252.455426)
		(width 0.18288)
		(layer "In11.Cu")
		(net "M_D_CPU0_SB_CA<1>")
	)
	(segment
		(start 324.255384 -248.691146)
		(end 322.80606 -250.14047)
		(width 0.18288)
		(layer "In11.Cu")
		(net "M_D_CPU0_SB_CA<1>")
	)
	(segment
		(start 293.309294 -252.480826)
		(end 292.251892 -252.480826)
		(width 0.18288)
		(layer "In11.Cu")
		(net "M_D_CPU0_SB_CA<1>")
	)
	(segment
		(start 314.445142 -249.798078)
		(end 311.407302 -249.798078)
		(width 0.18288)
		(layer "In11.Cu")
		(net "M_D_CPU0_SB_CA<1>")
	)
	(segment
		(start 346.736416 -248.263156)
		(end 346.647516 -248.287032)
		(width 0.088646)
		(layer "In11.Cu")
		(net "M_D_CPU0_SB_CA<1>")
	)
	(segment
		(start 281.117294 -252.389386)
		(end 280.694892 -252.389386)
		(width 0.18288)
		(layer "In11.Cu")
		(net "M_D_CPU0_SB_CA<1>")
	)
	(segment
		(start 295.6433 -252.455426)
		(end 295.329102 -252.141228)
		(width 0.18288)
		(layer "In11.Cu")
		(net "M_D_CPU0_SB_CA<1>")
	)
	(segment
		(start 322.80606 -250.14047)
		(end 314.787534 -250.14047)
		(width 0.18288)
		(layer "In11.Cu")
		(net "M_D_CPU0_SB_CA<1>")
	)
	(segment
		(start 297.411394 -252.455426)
		(end 296.972228 -252.455426)
		(width 0.18288)
		(layer "In11.Cu")
		(net "M_D_CPU0_SB_CA<1>")
	)
	(segment
		(start 310.682894 -250.522486)
		(end 309.552594 -250.522486)
		(width 0.18288)
		(layer "In11.Cu")
		(net "M_D_CPU0_SB_CA<1>")
	)
	(segment
		(start 303.883314 -251.406406)
		(end 302.808894 -252.480826)
		(width 0.18288)
		(layer "In11.Cu")
		(net "M_D_CPU0_SB_CA<1>")
	)
	(segment
		(start 314.787534 -250.14047)
		(end 314.445142 -249.798078)
		(width 0.18288)
		(layer "In11.Cu")
		(net "M_D_CPU0_SB_CA<1>")
	)
	(segment
		(start 288.22142 -252.0315)
		(end 288.026094 -252.226826)
		(width 0.18288)
		(layer "In11.Cu")
		(net "M_D_CPU0_SB_CA<1>")
	)
	(segment
		(start 274.622514 -251.924058)
		(end 273.596862 -251.924058)
		(width 0.18288)
		(layer "In11.Cu")
		(net "M_D_CPU0_SB_CA<1>")
	)
	(segment
		(start 289.989514 -252.0315)
		(end 288.22142 -252.0315)
		(width 0.18288)
		(layer "In11.Cu")
		(net "M_D_CPU0_SB_CA<1>")
	)
	(segment
		(start 274.815554 -252.378718)
		(end 274.815554 -252.117098)
		(width 0.18288)
		(layer "In11.Cu")
		(net "M_D_CPU0_SB_CA<1>")
	)
	(segment
		(start 270.814038 -252.430026)
		(end 269.542514 -252.430026)
		(width 0.18288)
		(layer "In11.Cu")
		(net "M_D_CPU0_SB_CA<1>")
	)
	(segment
		(start 275.709634 -251.924058)
		(end 275.516594 -252.117098)
		(width 0.18288)
		(layer "In11.Cu")
		(net "M_D_CPU0_SB_CA<1>")
	)
	(segment
		(start 278.348948 -252.141228)
		(end 278.074628 -252.415548)
		(width 0.18288)
		(layer "In11.Cu")
		(net "M_D_CPU0_SB_CA<1>")
	)
	(segment
		(start 275.516594 -252.378718)
		(end 275.323554 -252.571758)
		(width 0.18288)
		(layer "In11.Cu")
		(net "M_D_CPU0_SB_CA<1>")
	)
	(segment
		(start 300.100746 -252.480826)
		(end 299.760894 -252.140974)
		(width 0.18288)
		(layer "In11.Cu")
		(net "M_D_CPU0_SB_CA<1>")
	)
	(segment
		(start 275.008594 -252.571758)
		(end 274.815554 -252.378718)
		(width 0.18288)
		(layer "In11.Cu")
		(net "M_D_CPU0_SB_CA<1>")
	)
	(segment
		(start 269.542514 -252.430026)
		(end 268.829282 -251.716794)
		(width 0.18288)
		(layer "In11.Cu")
		(net "M_D_CPU0_SB_CA<1>")
	)
	(segment
		(start 271.007078 -251.879354)
		(end 271.007078 -252.236986)
		(width 0.18288)
		(layer "In11.Cu")
		(net "M_D_CPU0_SB_CA<1>")
	)
	(segment
		(start 275.516594 -252.117098)
		(end 275.516594 -252.378718)
		(width 0.18288)
		(layer "In11.Cu")
		(net "M_D_CPU0_SB_CA<1>")
	)
	(segment
		(start 280.694892 -252.389386)
		(end 280.446734 -252.141228)
		(width 0.18288)
		(layer "In11.Cu")
		(net "M_D_CPU0_SB_CA<1>")
	)
	(segment
		(start 342.284558 -250.057666)
		(end 336.303112 -250.057666)
		(width 0.18288)
		(layer "In11.Cu")
		(net "M_D_CPU0_SB_CA<1>")
	)
	(segment
		(start 292.251892 -252.480826)
		(end 291.802566 -252.0315)
		(width 0.18288)
		(layer "In11.Cu")
		(net "M_D_CPU0_SB_CA<1>")
	)
	(segment
		(start 295.329102 -252.141228)
		(end 293.648892 -252.141228)
		(width 0.18288)
		(layer "In11.Cu")
		(net "M_D_CPU0_SB_CA<1>")
	)
	(segment
		(start 311.407302 -249.798078)
		(end 310.682894 -250.522486)
		(width 0.18288)
		(layer "In11.Cu")
		(net "M_D_CPU0_SB_CA<1>")
	)
	(segment
		(start 282.290012 -252.389386)
		(end 281.917648 -252.017022)
		(width 0.18288)
		(layer "In11.Cu")
		(net "M_D_CPU0_SB_CA<1>")
	)
	(segment
		(start 280.446734 -252.141228)
		(end 278.348948 -252.141228)
		(width 0.18288)
		(layer "In11.Cu")
		(net "M_D_CPU0_SB_CA<1>")
	)
	(segment
		(start 273.596862 -251.924058)
		(end 273.090894 -252.430026)
		(width 0.18288)
		(layer "In11.Cu")
		(net "M_D_CPU0_SB_CA<1>")
	)
	(segment
		(start 296.28338 -252.140974)
		(end 295.968928 -252.455426)
		(width 0.18288)
		(layer "In11.Cu")
		(net "M_D_CPU0_SB_CA<1>")
	)
	(segment
		(start 273.090894 -252.430026)
		(end 271.901158 -252.430026)
		(width 0.18288)
		(layer "In11.Cu")
		(net "M_D_CPU0_SB_CA<1>")
	)
	(segment
		(start 286.743394 -252.379226)
		(end 284.885892 -252.379226)
		(width 0.18288)
		(layer "In11.Cu")
		(net "M_D_CPU0_SB_CA<1>")
	)
	(segment
		(start 345.858084 -248.787666)
		(end 345.858084 -248.806208)
		(width 0.088646)
		(layer "In11.Cu")
		(net "M_D_CPU0_SB_CA<1>")
	)
	(segment
		(start 284.885892 -252.379226)
		(end 284.647894 -252.141228)
		(width 0.18288)
		(layer "In11.Cu")
		(net "M_D_CPU0_SB_CA<1>")
	)
	(segment
		(start 336.303112 -250.057666)
		(end 336.17535 -249.929904)
		(width 0.18288)
		(layer "In11.Cu")
		(net "M_D_CPU0_SB_CA<1>")
	)
	(segment
		(start 290.917122 -252.407166)
		(end 290.36518 -252.407166)
		(width 0.18288)
		(layer "In11.Cu")
		(net "M_D_CPU0_SB_CA<1>")
	)
	(segment
		(start 345.194382 -250.057666)
		(end 342.284558 -250.057666)
		(width 0.088646)
		(layer "In11.Cu")
		(net "M_D_CPU0_SB_CA<1>")
	)
	(segment
		(start 277.353014 -252.415548)
		(end 276.861524 -251.924058)
		(width 0.18288)
		(layer "In11.Cu")
		(net "M_D_CPU0_SB_CA<1>")
	)
	(segment
		(start 282.960572 -252.141228)
		(end 282.712414 -252.389386)
		(width 0.18288)
		(layer "In11.Cu")
		(net "M_D_CPU0_SB_CA<1>")
	)
	(segment
		(start 345.38793 -249.620024)
		(end 345.38793 -249.90933)
		(width 0.088646)
		(layer "In11.Cu")
		(net "M_D_CPU0_SB_CA<1>")
	)
	(segment
		(start 346.893134 -247.992138)
		(end 346.893134 -247.992392)
		(width 0.088646)
		(layer "In11.Cu")
		(net "M_D_CPU0_SB_CA<1>")
	)
	(segment
		(start 271.515078 -251.686314)
		(end 271.200118 -251.686314)
		(width 0.18288)
		(layer "In11.Cu")
		(net "M_D_CPU0_SB_CA<1>")
	)
	(segment
		(start 274.815554 -252.117098)
		(end 274.622514 -251.924058)
		(width 0.18288)
		(layer "In11.Cu")
		(net "M_D_CPU0_SB_CA<1>")
	)
	(segment
		(start 271.200118 -251.686314)
		(end 271.007078 -251.879354)
		(width 0.18288)
		(layer "In11.Cu")
		(net "M_D_CPU0_SB_CA<1>")
	)
	(segment
		(start 271.708118 -252.236986)
		(end 271.708118 -251.879354)
		(width 0.18288)
		(layer "In11.Cu")
		(net "M_D_CPU0_SB_CA<1>")
	)
	(segment
		(start 275.323554 -252.571758)
		(end 275.008594 -252.571758)
		(width 0.18288)
		(layer "In11.Cu")
		(net "M_D_CPU0_SB_CA<1>")
	)
	(segment
		(start 271.901158 -252.430026)
		(end 271.708118 -252.236986)
		(width 0.18288)
		(layer "In11.Cu")
		(net "M_D_CPU0_SB_CA<1>")
	)
	(segment
		(start 296.972228 -252.455426)
		(end 296.657776 -252.140974)
		(width 0.18288)
		(layer "In11.Cu")
		(net "M_D_CPU0_SB_CA<1>")
	)
	(segment
		(start 276.861524 -251.924058)
		(end 275.709634 -251.924058)
		(width 0.18288)
		(layer "In11.Cu")
		(net "M_D_CPU0_SB_CA<1>")
	)
	(segment
		(start 271.708118 -251.879354)
		(end 271.515078 -251.686314)
		(width 0.18288)
		(layer "In11.Cu")
		(net "M_D_CPU0_SB_CA<1>")
	)
	(segment
		(start 296.657776 -252.140974)
		(end 296.28338 -252.140974)
		(width 0.18288)
		(layer "In11.Cu")
		(net "M_D_CPU0_SB_CA<1>")
	)
	(segment
		(start 345.679522 -249.125486)
		(end 345.670632 -249.130566)
		(width 0.088646)
		(layer "In11.Cu")
		(net "M_D_CPU0_SB_CA<1>")
	)
	(segment
		(start 286.895794 -252.226826)
		(end 286.743394 -252.379226)
		(width 0.18288)
		(layer "In11.Cu")
		(net "M_D_CPU0_SB_CA<1>")
	)
	(segment
		(start 307.040534 -251.406406)
		(end 303.883314 -251.406406)
		(width 0.18288)
		(layer "In11.Cu")
		(net "M_D_CPU0_SB_CA<1>")
	)
	(segment
		(start 299.760894 -252.140974)
		(end 297.725846 -252.140974)
		(width 0.18288)
		(layer "In11.Cu")
		(net "M_D_CPU0_SB_CA<1>")
	)
	(segment
		(start 308.91607 -251.15901)
		(end 307.28793 -251.15901)
		(width 0.18288)
		(layer "In11.Cu")
		(net "M_D_CPU0_SB_CA<1>")
	)
	(segment
		(start 284.647894 -252.141228)
		(end 282.960572 -252.141228)
		(width 0.18288)
		(layer "In11.Cu")
		(net "M_D_CPU0_SB_CA<1>")
	)
	(segment
		(start 271.007078 -252.236986)
		(end 270.814038 -252.430026)
		(width 0.18288)
		(layer "In11.Cu")
		(net "M_D_CPU0_SB_CA<1>")
	)
	(segment
		(start 346.893134 -247.992392)
		(end 346.736416 -248.263156)
		(width 0.088646)
		(layer "In11.Cu")
		(net "M_D_CPU0_SB_CA<1>")
	)
	(segment
		(start 278.074628 -252.415548)
		(end 277.353014 -252.415548)
		(width 0.18288)
		(layer "In11.Cu")
		(net "M_D_CPU0_SB_CA<1>")
	)
	(segment
		(start 281.917648 -252.017022)
		(end 281.489658 -252.017022)
		(width 0.18288)
		(layer "In11.Cu")
		(net "M_D_CPU0_SB_CA<1>")
	)
	(segment
		(start 309.552594 -250.522486)
		(end 308.91607 -251.15901)
		(width 0.18288)
		(layer "In11.Cu")
		(net "M_D_CPU0_SB_CA<1>")
	)
	(segment
		(start 293.648892 -252.141228)
		(end 293.309294 -252.480826)
		(width 0.18288)
		(layer "In11.Cu")
		(net "M_D_CPU0_SB_CA<1>")
	)
	(segment
		(start 281.489658 -252.017022)
		(end 281.117294 -252.389386)
		(width 0.18288)
		(layer "In11.Cu")
		(net "M_D_CPU0_SB_CA<1>")
	)
	(segment
		(start 302.808894 -252.480826)
		(end 300.100746 -252.480826)
		(width 0.18288)
		(layer "In11.Cu")
		(net "M_D_CPU0_SB_CA<1>")
	)
	(segment
		(start 295.968928 -252.455426)
		(end 295.6433 -252.455426)
		(width 0.18288)
		(layer "In11.Cu")
		(net "M_D_CPU0_SB_CA<1>")
	)
	(segment
		(start 288.026094 -252.226826)
		(end 286.895794 -252.226826)
		(width 0.18288)
		(layer "In11.Cu")
		(net "M_D_CPU0_SB_CA<1>")
	)
	(segment
		(start 282.712414 -252.389386)
		(end 282.290012 -252.389386)
		(width 0.18288)
		(layer "In11.Cu")
		(net "M_D_CPU0_SB_CA<1>")
	)
	(segment
		(start 291.802566 -252.0315)
		(end 291.292788 -252.0315)
		(width 0.18288)
		(layer "In11.Cu")
		(net "M_D_CPU0_SB_CA<1>")
	)
	(segment
		(start 307.28793 -251.15901)
		(end 307.040534 -251.406406)
		(width 0.18288)
		(layer "In11.Cu")
		(net "M_D_CPU0_SB_CA<1>")
	)
	(arc
		(start 345.664536 -249.134122)
		(mid 345.461949 -249.340473)
		(end 345.38793 -249.620024)
		(width 0.088646)
		(layer "In11.Cu")
		(net "M_D_CPU0_SB_CA<1>")
	)
	(arc
		(start 346.647516 -248.287032)
		(mid 346.390517 -248.241606)
		(end 346.140532 -248.316496)
		(width 0.088646)
		(layer "In11.Cu")
		(net "M_D_CPU0_SB_CA<1>")
	)
	(arc
		(start 346.140532 -248.316496)
		(mid 345.938246 -248.515477)
		(end 345.858084 -248.787666)
		(width 0.088646)
		(layer "In11.Cu")
		(net "M_D_CPU0_SB_CA<1>")
	)
	(arc
		(start 345.38793 -249.90933)
		(mid 345.379075 -249.953848)
		(end 345.353894 -249.991626)
		(width 0.088646)
		(layer "In11.Cu")
		(net "M_D_CPU0_SB_CA<1>")
	)
	(arc
		(start 345.353894 -249.991626)
		(mid 345.280709 -250.040526)
		(end 345.194382 -250.057666)
		(width 0.088646)
		(layer "In11.Cu")
		(net "M_D_CPU0_SB_CA<1>")
	)
	(arc
		(start 345.858084 -248.806208)
		(mid 345.810405 -248.989108)
		(end 345.679522 -249.125486)
		(width 0.088646)
		(layer "In11.Cu")
		(net "M_D_CPU0_SB_CA<1>")
	)
	(segment
		(start 261.050786 -252.141736)
		(end 259.065268 -252.141736)
		(width 0.1016)
		(layer "F.Cu")
		(net "M_D_CPU0_SB_CA<0>")
	)
	(segment
		(start 258.130548 -252.778006)
		(end 257.626104 -252.778006)
		(width 0.20066)
		(layer "F.Cu")
		(net "M_D_CPU0_SB_CA<0>")
	)
	(segment
		(start 259.065268 -252.141736)
		(end 259.056378 -252.132846)
		(width 0.1016)
		(layer "F.Cu")
		(net "M_D_CPU0_SB_CA<0>")
	)
	(segment
		(start 346.423234 -249.341894)
		(end 346.423234 -248.806208)
		(width 0.20066)
		(layer "F.Cu")
		(net "M_D_CPU0_SB_CA<0>")
	)
	(segment
		(start 259.056378 -252.132846)
		(end 258.44754 -252.132846)
		(width 0.20066)
		(layer "F.Cu")
		(net "M_D_CPU0_SB_CA<0>")
	)
	(segment
		(start 263.624314 -252.566678)
		(end 261.984998 -252.566678)
		(width 0.20066)
		(layer "F.Cu")
		(net "M_D_CPU0_SB_CA<0>")
	)
	(segment
		(start 264.729214 -252.566678)
		(end 263.624314 -252.566678)
		(width 0.20066)
		(layer "F.Cu")
		(net "M_D_CPU0_SB_CA<0>")
	)
	(segment
		(start 261.560056 -252.141736)
		(end 261.381494 -252.141736)
		(width 0.20066)
		(layer "F.Cu")
		(net "M_D_CPU0_SB_CA<0>")
	)
	(segment
		(start 258.28498 -252.295406)
		(end 258.28498 -252.623574)
		(width 0.20066)
		(layer "F.Cu")
		(net "M_D_CPU0_SB_CA<0>")
	)
	(segment
		(start 258.44754 -252.132846)
		(end 258.28498 -252.295406)
		(width 0.20066)
		(layer "F.Cu")
		(net "M_D_CPU0_SB_CA<0>")
	)
	(segment
		(start 257.626104 -252.778006)
		(end 257.414776 -252.566678)
		(width 0.20066)
		(layer "F.Cu")
		(net "M_D_CPU0_SB_CA<0>")
	)
	(segment
		(start 261.984998 -252.566678)
		(end 261.560056 -252.141736)
		(width 0.20066)
		(layer "F.Cu")
		(net "M_D_CPU0_SB_CA<0>")
	)
	(segment
		(start 346.42298 -249.342148)
		(end 346.423234 -249.341894)
		(width 0.20066)
		(layer "F.Cu")
		(net "M_D_CPU0_SB_CA<0>")
	)
	(segment
		(start 257.414776 -252.566678)
		(end 256.080514 -252.566678)
		(width 0.20066)
		(layer "F.Cu")
		(net "M_D_CPU0_SB_CA<0>")
	)
	(segment
		(start 258.28498 -252.623574)
		(end 258.130548 -252.778006)
		(width 0.20066)
		(layer "F.Cu")
		(net "M_D_CPU0_SB_CA<0>")
	)
	(segment
		(start 261.381494 -252.141736)
		(end 261.050786 -252.141736)
		(width 0.101854)
		(layer "F.Cu")
		(net "M_D_CPU0_SB_CA<0>")
	)
	(segment
		(start 309.638192 -251.267468)
		(end 309.171594 -251.734066)
		(width 0.18288)
		(layer "In11.Cu")
		(net "M_D_CPU0_SB_CA<0>")
	)
	(segment
		(start 286.893762 -252.991112)
		(end 284.176216 -252.991112)
		(width 0.18288)
		(layer "In11.Cu")
		(net "M_D_CPU0_SB_CA<0>")
	)
	(segment
		(start 267.858494 -252.709426)
		(end 266.06119 -252.709426)
		(width 0.18288)
		(layer "In11.Cu")
		(net "M_D_CPU0_SB_CA<0>")
	)
	(segment
		(start 279.965658 -253.09449)
		(end 279.584658 -253.09449)
		(width 0.18288)
		(layer "In11.Cu")
		(net "M_D_CPU0_SB_CA<0>")
	)
	(segment
		(start 284.0863 -253.081028)
		(end 283.812996 -253.081028)
		(width 0.18288)
		(layer "In11.Cu")
		(net "M_D_CPU0_SB_CA<0>")
	)
	(segment
		(start 294.67048 -252.991112)
		(end 289.725608 -252.991112)
		(width 0.18288)
		(layer "In11.Cu")
		(net "M_D_CPU0_SB_CA<0>")
	)
	(segment
		(start 305.516534 -251.924566)
		(end 304.193194 -251.924566)
		(width 0.18288)
		(layer "In11.Cu")
		(net "M_D_CPU0_SB_CA<0>")
	)
	(segment
		(start 323.002656 -250.66244)
		(end 314.587382 -250.66244)
		(width 0.18288)
		(layer "In11.Cu")
		(net "M_D_CPU0_SB_CA<0>")
	)
	(segment
		(start 346.579698 -248.53519)
		(end 346.558616 -248.457212)
		(width 0.088646)
		(layer "In11.Cu")
		(net "M_D_CPU0_SB_CA<0>")
	)
	(segment
		(start 283.812996 -253.081028)
		(end 283.72308 -252.991112)
		(width 0.18288)
		(layer "In11.Cu")
		(net "M_D_CPU0_SB_CA<0>")
	)
	(segment
		(start 275.847556 -253.115826)
		(end 273.700494 -253.115826)
		(width 0.18288)
		(layer "In11.Cu")
		(net "M_D_CPU0_SB_CA<0>")
	)
	(segment
		(start 342.928194 -250.27128)
		(end 342.619076 -250.580398)
		(width 0.088646)
		(layer "In11.Cu")
		(net "M_D_CPU0_SB_CA<0>")
	)
	(segment
		(start 345.366848 -250.27128)
		(end 342.928194 -250.27128)
		(width 0.088646)
		(layer "In11.Cu")
		(net "M_D_CPU0_SB_CA<0>")
	)
	(segment
		(start 298.808394 -253.039626)
		(end 298.75988 -252.991112)
		(width 0.18288)
		(layer "In11.Cu")
		(net "M_D_CPU0_SB_CA<0>")
	)
	(segment
		(start 283.72308 -252.991112)
		(end 280.069036 -252.991112)
		(width 0.18288)
		(layer "In11.Cu")
		(net "M_D_CPU0_SB_CA<0>")
	)
	(segment
		(start 299.256704 -252.991112)
		(end 299.20819 -253.039626)
		(width 0.18288)
		(layer "In11.Cu")
		(net "M_D_CPU0_SB_CA<0>")
	)
	(segment
		(start 345.771978 -249.29211)
		(end 345.765882 -249.295666)
		(width 0.088646)
		(layer "In11.Cu")
		(net "M_D_CPU0_SB_CA<0>")
	)
	(segment
		(start 295.123616 -252.991112)
		(end 295.069514 -253.045214)
		(width 0.18288)
		(layer "In11.Cu")
		(net "M_D_CPU0_SB_CA<0>")
	)
	(segment
		(start 324.62851 -249.036586)
		(end 323.002656 -250.66244)
		(width 0.18288)
		(layer "In11.Cu")
		(net "M_D_CPU0_SB_CA<0>")
	)
	(segment
		(start 280.069036 -252.991112)
		(end 279.965658 -253.09449)
		(width 0.18288)
		(layer "In11.Cu")
		(net "M_D_CPU0_SB_CA<0>")
	)
	(segment
		(start 342.284558 -250.580398)
		(end 333.591662 -250.580398)
		(width 0.18288)
		(layer "In11.Cu")
		(net "M_D_CPU0_SB_CA<0>")
	)
	(segment
		(start 289.677094 -253.039626)
		(end 289.080194 -253.039626)
		(width 0.18288)
		(layer "In11.Cu")
		(net "M_D_CPU0_SB_CA<0>")
	)
	(segment
		(start 346.236036 -248.48185)
		(end 346.227146 -248.48693)
		(width 0.088646)
		(layer "In11.Cu")
		(net "M_D_CPU0_SB_CA<0>")
	)
	(segment
		(start 309.171594 -251.734066)
		(end 308.518814 -251.734066)
		(width 0.18288)
		(layer "In11.Cu")
		(net "M_D_CPU0_SB_CA<0>")
	)
	(segment
		(start 295.069514 -253.045214)
		(end 294.724582 -253.045214)
		(width 0.18288)
		(layer "In11.Cu")
		(net "M_D_CPU0_SB_CA<0>")
	)
	(segment
		(start 279.584658 -253.09449)
		(end 279.48128 -252.991112)
		(width 0.18288)
		(layer "In11.Cu")
		(net "M_D_CPU0_SB_CA<0>")
	)
	(segment
		(start 268.253718 -253.10465)
		(end 267.858494 -252.709426)
		(width 0.18288)
		(layer "In11.Cu")
		(net "M_D_CPU0_SB_CA<0>")
	)
	(segment
		(start 333.591662 -250.580398)
		(end 333.258414 -250.913646)
		(width 0.18288)
		(layer "In11.Cu")
		(net "M_D_CPU0_SB_CA<0>")
	)
	(segment
		(start 294.724582 -253.045214)
		(end 294.67048 -252.991112)
		(width 0.18288)
		(layer "In11.Cu")
		(net "M_D_CPU0_SB_CA<0>")
	)
	(segment
		(start 304.193194 -251.924566)
		(end 303.126648 -252.991112)
		(width 0.18288)
		(layer "In11.Cu")
		(net "M_D_CPU0_SB_CA<0>")
	)
	(segment
		(start 314.587382 -250.66244)
		(end 314.333128 -250.408186)
		(width 0.18288)
		(layer "In11.Cu")
		(net "M_D_CPU0_SB_CA<0>")
	)
	(segment
		(start 342.619076 -250.580398)
		(end 342.284558 -250.580398)
		(width 0.088646)
		(layer "In11.Cu")
		(net "M_D_CPU0_SB_CA<0>")
	)
	(segment
		(start 269.19047 -253.10465)
		(end 268.253718 -253.10465)
		(width 0.18288)
		(layer "In11.Cu")
		(net "M_D_CPU0_SB_CA<0>")
	)
	(segment
		(start 333.258414 -250.913646)
		(end 329.296014 -250.913646)
		(width 0.18288)
		(layer "In11.Cu")
		(net "M_D_CPU0_SB_CA<0>")
	)
	(segment
		(start 266.06119 -252.709426)
		(end 265.918442 -252.566678)
		(width 0.18288)
		(layer "In11.Cu")
		(net "M_D_CPU0_SB_CA<0>")
	)
	(segment
		(start 273.700494 -253.115826)
		(end 273.57578 -252.991112)
		(width 0.18288)
		(layer "In11.Cu")
		(net "M_D_CPU0_SB_CA<0>")
	)
	(segment
		(start 305.813714 -252.221746)
		(end 305.516534 -251.924566)
		(width 0.18288)
		(layer "In11.Cu")
		(net "M_D_CPU0_SB_CA<0>")
	)
	(segment
		(start 269.304008 -252.991112)
		(end 269.19047 -253.10465)
		(width 0.18288)
		(layer "In11.Cu")
		(net "M_D_CPU0_SB_CA<0>")
	)
	(segment
		(start 311.714134 -250.408186)
		(end 310.854852 -251.267468)
		(width 0.18288)
		(layer "In11.Cu")
		(net "M_D_CPU0_SB_CA<0>")
	)
	(segment
		(start 308.031134 -252.221746)
		(end 305.813714 -252.221746)
		(width 0.18288)
		(layer "In11.Cu")
		(net "M_D_CPU0_SB_CA<0>")
	)
	(segment
		(start 299.20819 -253.039626)
		(end 298.808394 -253.039626)
		(width 0.18288)
		(layer "In11.Cu")
		(net "M_D_CPU0_SB_CA<0>")
	)
	(segment
		(start 345.578684 -250.059444)
		(end 345.366848 -250.27128)
		(width 0.088646)
		(layer "In11.Cu")
		(net "M_D_CPU0_SB_CA<0>")
	)
	(segment
		(start 329.296014 -250.913646)
		(end 327.418954 -249.036586)
		(width 0.18288)
		(layer "In11.Cu")
		(net "M_D_CPU0_SB_CA<0>")
	)
	(segment
		(start 327.418954 -249.036586)
		(end 324.62851 -249.036586)
		(width 0.18288)
		(layer "In11.Cu")
		(net "M_D_CPU0_SB_CA<0>")
	)
	(segment
		(start 289.725608 -252.991112)
		(end 289.677094 -253.039626)
		(width 0.18288)
		(layer "In11.Cu")
		(net "M_D_CPU0_SB_CA<0>")
	)
	(segment
		(start 279.48128 -252.991112)
		(end 275.97227 -252.991112)
		(width 0.18288)
		(layer "In11.Cu")
		(net "M_D_CPU0_SB_CA<0>")
	)
	(segment
		(start 286.997648 -252.887226)
		(end 286.893762 -252.991112)
		(width 0.18288)
		(layer "In11.Cu")
		(net "M_D_CPU0_SB_CA<0>")
	)
	(segment
		(start 284.176216 -252.991112)
		(end 284.0863 -253.081028)
		(width 0.18288)
		(layer "In11.Cu")
		(net "M_D_CPU0_SB_CA<0>")
	)
	(segment
		(start 303.126648 -252.991112)
		(end 299.256704 -252.991112)
		(width 0.18288)
		(layer "In11.Cu")
		(net "M_D_CPU0_SB_CA<0>")
	)
	(segment
		(start 265.918442 -252.566678)
		(end 264.729214 -252.566678)
		(width 0.18288)
		(layer "In11.Cu")
		(net "M_D_CPU0_SB_CA<0>")
	)
	(segment
		(start 308.518814 -251.734066)
		(end 308.031134 -252.221746)
		(width 0.18288)
		(layer "In11.Cu")
		(net "M_D_CPU0_SB_CA<0>")
	)
	(segment
		(start 289.080194 -253.039626)
		(end 288.927794 -252.887226)
		(width 0.18288)
		(layer "In11.Cu")
		(net "M_D_CPU0_SB_CA<0>")
	)
	(segment
		(start 288.927794 -252.887226)
		(end 286.997648 -252.887226)
		(width 0.18288)
		(layer "In11.Cu")
		(net "M_D_CPU0_SB_CA<0>")
	)
	(segment
		(start 298.75988 -252.991112)
		(end 295.123616 -252.991112)
		(width 0.18288)
		(layer "In11.Cu")
		(net "M_D_CPU0_SB_CA<0>")
	)
	(segment
		(start 345.578684 -249.611388)
		(end 345.578684 -250.059444)
		(width 0.088646)
		(layer "In11.Cu")
		(net "M_D_CPU0_SB_CA<0>")
	)
	(segment
		(start 346.423234 -248.806208)
		(end 346.579698 -248.53519)
		(width 0.088646)
		(layer "In11.Cu")
		(net "M_D_CPU0_SB_CA<0>")
	)
	(segment
		(start 310.854852 -251.267468)
		(end 309.638192 -251.267468)
		(width 0.18288)
		(layer "In11.Cu")
		(net "M_D_CPU0_SB_CA<0>")
	)
	(segment
		(start 273.57578 -252.991112)
		(end 269.304008 -252.991112)
		(width 0.18288)
		(layer "In11.Cu")
		(net "M_D_CPU0_SB_CA<0>")
	)
	(segment
		(start 275.97227 -252.991112)
		(end 275.847556 -253.115826)
		(width 0.18288)
		(layer "In11.Cu")
		(net "M_D_CPU0_SB_CA<0>")
	)
	(segment
		(start 314.333128 -250.408186)
		(end 311.714134 -250.408186)
		(width 0.18288)
		(layer "In11.Cu")
		(net "M_D_CPU0_SB_CA<0>")
	)
	(arc
		(start 345.765882 -249.295666)
		(mid 345.630949 -249.42902)
		(end 345.578684 -249.611388)
		(width 0.088646)
		(layer "In11.Cu")
		(net "M_D_CPU0_SB_CA<0>")
	)
	(arc
		(start 346.558616 -248.457212)
		(mid 346.39452 -248.432865)
		(end 346.236036 -248.48185)
		(width 0.088646)
		(layer "In11.Cu")
		(net "M_D_CPU0_SB_CA<0>")
	)
	(arc
		(start 346.048584 -248.806208)
		(mid 345.974593 -249.085774)
		(end 345.771978 -249.29211)
		(width 0.088646)
		(layer "In11.Cu")
		(net "M_D_CPU0_SB_CA<0>")
	)
	(arc
		(start 346.227146 -248.48693)
		(mid 346.096232 -248.62329)
		(end 346.048584 -248.806208)
		(width 0.088646)
		(layer "In11.Cu")
		(net "M_D_CPU0_SB_CA<0>")
	)
	(segment
		(start 264.729214 -244.066568)
		(end 263.624314 -244.066568)
		(width 0.20066)
		(layer "F.Cu")
		(net "M_D_CPU0_SA_RSP<1>")
	)
	(segment
		(start 343.243916 -256.361184)
		(end 343.243662 -256.361438)
		(width 0.20066)
		(layer "F.Cu")
		(net "M_D_CPU0_SA_RSP<1>")
	)
	(segment
		(start 343.243916 -255.825498)
		(end 343.243916 -256.361184)
		(width 0.20066)
		(layer "F.Cu")
		(net "M_D_CPU0_SA_RSP<1>")
	)
	(segment
		(start 268.479524 -256.79146)
		(end 267.716508 -256.028444)
		(width 0.18288)
		(layer "In6.Cu")
		(net "M_D_CPU0_SA_RSP<1>")
	)
	(segment
		(start 263.395714 -254.422656)
		(end 263.212834 -254.239776)
		(width 0.18288)
		(layer "In6.Cu")
		(net "M_D_CPU0_SA_RSP<1>")
	)
	(segment
		(start 262.02132 -252.350016)
		(end 262.2042 -252.167136)
		(width 0.18288)
		(layer "In6.Cu")
		(net "M_D_CPU0_SA_RSP<1>")
	)
	(segment
		(start 319.069466 -256.79146)
		(end 319.069212 -256.791206)
		(width 0.18288)
		(layer "In6.Cu")
		(net "M_D_CPU0_SA_RSP<1>")
	)
	(segment
		(start 263.212834 -253.548896)
		(end 263.395714 -253.366016)
		(width 0.18288)
		(layer "In6.Cu")
		(net "M_D_CPU0_SA_RSP<1>")
	)
	(segment
		(start 331.966062 -255.986534)
		(end 331.727556 -255.986534)
		(width 0.088646)
		(layer "In6.Cu")
		(net "M_D_CPU0_SA_RSP<1>")
	)
	(segment
		(start 263.395714 -253.366016)
		(end 263.395714 -253.040896)
		(width 0.18288)
		(layer "In6.Cu")
		(net "M_D_CPU0_SA_RSP<1>")
	)
	(segment
		(start 331.582268 -255.841246)
		(end 331.028802 -255.841246)
		(width 0.088646)
		(layer "In6.Cu")
		(net "M_D_CPU0_SA_RSP<1>")
	)
	(segment
		(start 263.212834 -252.167136)
		(end 263.395714 -251.984256)
		(width 0.18288)
		(layer "In6.Cu")
		(net "M_D_CPU0_SA_RSP<1>")
	)
	(segment
		(start 337.417664 -256.03708)
		(end 337.402932 -256.045716)
		(width 0.088646)
		(layer "In6.Cu")
		(net "M_D_CPU0_SA_RSP<1>")
	)
	(segment
		(start 343.243662 -256.361438)
		(end 342.860884 -256.21996)
		(width 0.088646)
		(layer "In6.Cu")
		(net "M_D_CPU0_SA_RSP<1>")
	)
	(segment
		(start 314.41517 -256.79146)
		(end 268.479524 -256.79146)
		(width 0.18288)
		(layer "In6.Cu")
		(net "M_D_CPU0_SA_RSP<1>")
	)
	(segment
		(start 262.02132 -252.675136)
		(end 262.02132 -252.350016)
		(width 0.18288)
		(layer "In6.Cu")
		(net "M_D_CPU0_SA_RSP<1>")
	)
	(segment
		(start 339.297264 -256.03708)
		(end 339.282532 -256.045716)
		(width 0.088646)
		(layer "In6.Cu")
		(net "M_D_CPU0_SA_RSP<1>")
	)
	(segment
		(start 326.778874 -256.79146)
		(end 319.069466 -256.79146)
		(width 0.18288)
		(layer "In6.Cu")
		(net "M_D_CPU0_SA_RSP<1>")
	)
	(segment
		(start 262.2042 -253.548896)
		(end 263.212834 -253.548896)
		(width 0.18288)
		(layer "In6.Cu")
		(net "M_D_CPU0_SA_RSP<1>")
	)
	(segment
		(start 263.395714 -255.061212)
		(end 263.395714 -254.422656)
		(width 0.18288)
		(layer "In6.Cu")
		(net "M_D_CPU0_SA_RSP<1>")
	)
	(segment
		(start 263.212834 -254.239776)
		(end 262.2042 -254.239776)
		(width 0.18288)
		(layer "In6.Cu")
		(net "M_D_CPU0_SA_RSP<1>")
	)
	(segment
		(start 331.028802 -255.841246)
		(end 329.073002 -255.841246)
		(width 0.18288)
		(layer "In6.Cu")
		(net "M_D_CPU0_SA_RSP<1>")
	)
	(segment
		(start 263.395714 -244.645434)
		(end 263.97458 -244.066568)
		(width 0.18288)
		(layer "In6.Cu")
		(net "M_D_CPU0_SA_RSP<1>")
	)
	(segment
		(start 263.395714 -253.040896)
		(end 263.212834 -252.858016)
		(width 0.18288)
		(layer "In6.Cu")
		(net "M_D_CPU0_SA_RSP<1>")
	)
	(segment
		(start 263.97458 -244.066568)
		(end 264.729214 -244.066568)
		(width 0.18288)
		(layer "In6.Cu")
		(net "M_D_CPU0_SA_RSP<1>")
	)
	(segment
		(start 262.2042 -252.167136)
		(end 263.212834 -252.167136)
		(width 0.18288)
		(layer "In6.Cu")
		(net "M_D_CPU0_SA_RSP<1>")
	)
	(segment
		(start 262.2042 -252.858016)
		(end 262.02132 -252.675136)
		(width 0.18288)
		(layer "In6.Cu")
		(net "M_D_CPU0_SA_RSP<1>")
	)
	(segment
		(start 263.212834 -252.858016)
		(end 262.2042 -252.858016)
		(width 0.18288)
		(layer "In6.Cu")
		(net "M_D_CPU0_SA_RSP<1>")
	)
	(segment
		(start 331.727556 -255.986534)
		(end 331.582268 -255.841246)
		(width 0.088646)
		(layer "In6.Cu")
		(net "M_D_CPU0_SA_RSP<1>")
	)
	(segment
		(start 314.415424 -256.791206)
		(end 314.41517 -256.79146)
		(width 0.18288)
		(layer "In6.Cu")
		(net "M_D_CPU0_SA_RSP<1>")
	)
	(segment
		(start 262.02132 -254.056896)
		(end 262.02132 -253.731776)
		(width 0.18288)
		(layer "In6.Cu")
		(net "M_D_CPU0_SA_RSP<1>")
	)
	(segment
		(start 262.02132 -253.731776)
		(end 262.2042 -253.548896)
		(width 0.18288)
		(layer "In6.Cu")
		(net "M_D_CPU0_SA_RSP<1>")
	)
	(segment
		(start 329.073002 -255.841246)
		(end 326.778874 -256.79146)
		(width 0.18288)
		(layer "In6.Cu")
		(net "M_D_CPU0_SA_RSP<1>")
	)
	(segment
		(start 262.2042 -254.239776)
		(end 262.02132 -254.056896)
		(width 0.18288)
		(layer "In6.Cu")
		(net "M_D_CPU0_SA_RSP<1>")
	)
	(segment
		(start 263.395714 -251.984256)
		(end 263.395714 -244.645434)
		(width 0.18288)
		(layer "In6.Cu")
		(net "M_D_CPU0_SA_RSP<1>")
	)
	(segment
		(start 267.716508 -256.028444)
		(end 264.362946 -256.028444)
		(width 0.18288)
		(layer "In6.Cu")
		(net "M_D_CPU0_SA_RSP<1>")
	)
	(segment
		(start 264.362946 -256.028444)
		(end 263.395714 -255.061212)
		(width 0.18288)
		(layer "In6.Cu")
		(net "M_D_CPU0_SA_RSP<1>")
	)
	(segment
		(start 342.116918 -256.03708)
		(end 342.106504 -256.043176)
		(width 0.088646)
		(layer "In6.Cu")
		(net "M_D_CPU0_SA_RSP<1>")
	)
	(segment
		(start 341.176864 -256.03708)
		(end 341.162132 -256.045716)
		(width 0.088646)
		(layer "In6.Cu")
		(net "M_D_CPU0_SA_RSP<1>")
	)
	(segment
		(start 319.069212 -256.791206)
		(end 314.415424 -256.791206)
		(width 0.18288)
		(layer "In6.Cu")
		(net "M_D_CPU0_SA_RSP<1>")
	)
	(segment
		(start 342.579452 -256.08788)
		(end 342.491314 -256.03708)
		(width 0.088646)
		(layer "In6.Cu")
		(net "M_D_CPU0_SA_RSP<1>")
	)
	(arc
		(start 341.55126 -256.03708)
		(mid 341.364062 -255.986937)
		(end 341.176864 -256.03708)
		(width 0.088646)
		(layer "In6.Cu")
		(net "M_D_CPU0_SA_RSP<1>")
	)
	(arc
		(start 337.79206 -256.03708)
		(mid 337.604862 -255.986937)
		(end 337.417664 -256.03708)
		(width 0.088646)
		(layer "In6.Cu")
		(net "M_D_CPU0_SA_RSP<1>")
	)
	(arc
		(start 337.402932 -256.045716)
		(mid 337.126457 -256.113036)
		(end 336.85226 -256.03708)
		(width 0.088646)
		(layer "In6.Cu")
		(net "M_D_CPU0_SA_RSP<1>")
	)
	(arc
		(start 342.860884 -256.21996)
		(mid 342.717384 -256.159852)
		(end 342.579452 -256.08788)
		(width 0.088646)
		(layer "In6.Cu")
		(net "M_D_CPU0_SA_RSP<1>")
	)
	(arc
		(start 333.658464 -256.03708)
		(mid 333.375762 -256.112856)
		(end 333.09306 -256.03708)
		(width 0.088646)
		(layer "In6.Cu")
		(net "M_D_CPU0_SA_RSP<1>")
	)
	(arc
		(start 334.598264 -256.03708)
		(mid 334.315562 -256.112856)
		(end 334.03286 -256.03708)
		(width 0.088646)
		(layer "In6.Cu")
		(net "M_D_CPU0_SA_RSP<1>")
	)
	(arc
		(start 335.538064 -256.03708)
		(mid 335.255362 -256.112856)
		(end 334.97266 -256.03708)
		(width 0.088646)
		(layer "In6.Cu")
		(net "M_D_CPU0_SA_RSP<1>")
	)
	(arc
		(start 339.67166 -256.03708)
		(mid 339.484462 -255.986937)
		(end 339.297264 -256.03708)
		(width 0.088646)
		(layer "In6.Cu")
		(net "M_D_CPU0_SA_RSP<1>")
	)
	(arc
		(start 338.73186 -256.03708)
		(mid 338.544662 -255.986937)
		(end 338.357464 -256.03708)
		(width 0.088646)
		(layer "In6.Cu")
		(net "M_D_CPU0_SA_RSP<1>")
	)
	(arc
		(start 334.97266 -256.03708)
		(mid 334.785462 -255.986937)
		(end 334.598264 -256.03708)
		(width 0.088646)
		(layer "In6.Cu")
		(net "M_D_CPU0_SA_RSP<1>")
	)
	(arc
		(start 333.09306 -256.03708)
		(mid 332.905862 -255.986937)
		(end 332.718664 -256.03708)
		(width 0.088646)
		(layer "In6.Cu")
		(net "M_D_CPU0_SA_RSP<1>")
	)
	(arc
		(start 335.91246 -256.03708)
		(mid 335.725262 -255.986937)
		(end 335.538064 -256.03708)
		(width 0.088646)
		(layer "In6.Cu")
		(net "M_D_CPU0_SA_RSP<1>")
	)
	(arc
		(start 342.491314 -256.03708)
		(mid 342.304116 -255.986937)
		(end 342.116918 -256.03708)
		(width 0.088646)
		(layer "In6.Cu")
		(net "M_D_CPU0_SA_RSP<1>")
	)
	(arc
		(start 340.237064 -256.03708)
		(mid 339.954362 -256.112856)
		(end 339.67166 -256.03708)
		(width 0.088646)
		(layer "In6.Cu")
		(net "M_D_CPU0_SA_RSP<1>")
	)
	(arc
		(start 336.85226 -256.03708)
		(mid 336.665062 -255.986937)
		(end 336.477864 -256.03708)
		(width 0.088646)
		(layer "In6.Cu")
		(net "M_D_CPU0_SA_RSP<1>")
	)
	(arc
		(start 332.15326 -256.03708)
		(mid 332.062988 -255.999481)
		(end 331.966062 -255.986534)
		(width 0.088646)
		(layer "In6.Cu")
		(net "M_D_CPU0_SA_RSP<1>")
	)
	(arc
		(start 338.357464 -256.03708)
		(mid 338.074762 -256.112856)
		(end 337.79206 -256.03708)
		(width 0.088646)
		(layer "In6.Cu")
		(net "M_D_CPU0_SA_RSP<1>")
	)
	(arc
		(start 340.61146 -256.03708)
		(mid 340.424262 -255.986937)
		(end 340.237064 -256.03708)
		(width 0.088646)
		(layer "In6.Cu")
		(net "M_D_CPU0_SA_RSP<1>")
	)
	(arc
		(start 334.03286 -256.03708)
		(mid 333.845662 -255.986937)
		(end 333.658464 -256.03708)
		(width 0.088646)
		(layer "In6.Cu")
		(net "M_D_CPU0_SA_RSP<1>")
	)
	(arc
		(start 341.162132 -256.045716)
		(mid 340.885657 -256.113036)
		(end 340.61146 -256.03708)
		(width 0.088646)
		(layer "In6.Cu")
		(net "M_D_CPU0_SA_RSP<1>")
	)
	(arc
		(start 339.282532 -256.045716)
		(mid 339.006057 -256.113036)
		(end 338.73186 -256.03708)
		(width 0.088646)
		(layer "In6.Cu")
		(net "M_D_CPU0_SA_RSP<1>")
	)
	(arc
		(start 336.477864 -256.03708)
		(mid 336.195162 -256.112856)
		(end 335.91246 -256.03708)
		(width 0.088646)
		(layer "In6.Cu")
		(net "M_D_CPU0_SA_RSP<1>")
	)
	(arc
		(start 332.718664 -256.03708)
		(mid 332.435962 -256.112856)
		(end 332.15326 -256.03708)
		(width 0.088646)
		(layer "In6.Cu")
		(net "M_D_CPU0_SA_RSP<1>")
	)
	(arc
		(start 342.106504 -256.043176)
		(mid 341.828072 -256.113022)
		(end 341.55126 -256.03708)
		(width 0.088646)
		(layer "In6.Cu")
		(net "M_D_CPU0_SA_RSP<1>")
	)
	(segment
		(start 343.713562 -257.175)
		(end 343.713816 -257.175254)
		(width 0.20066)
		(layer "F.Cu")
		(net "M_D_CPU0_SA_RSP<0>")
	)
	(segment
		(start 257.185414 -244.066568)
		(end 256.080514 -244.066568)
		(width 0.20066)
		(layer "F.Cu")
		(net "M_D_CPU0_SA_RSP<0>")
	)
	(segment
		(start 343.713562 -256.639314)
		(end 343.713562 -257.175)
		(width 0.20066)
		(layer "F.Cu")
		(net "M_D_CPU0_SA_RSP<0>")
	)
	(segment
		(start 258.041648 -250.72848)
		(end 257.025648 -250.72848)
		(width 0.18288)
		(layer "In6.Cu")
		(net "M_D_CPU0_SA_RSP<0>")
	)
	(segment
		(start 343.713816 -257.175254)
		(end 344.02649 -257.175254)
		(width 0.088646)
		(layer "In6.Cu")
		(net "M_D_CPU0_SA_RSP<0>")
	)
	(segment
		(start 319.291716 -258.055364)
		(end 319.069212 -257.83286)
		(width 0.18288)
		(layer "In6.Cu")
		(net "M_D_CPU0_SA_RSP<0>")
	)
	(segment
		(start 342.975946 -256.859532)
		(end 342.961214 -256.850896)
		(width 0.088646)
		(layer "In6.Cu")
		(net "M_D_CPU0_SA_RSP<0>")
	)
	(segment
		(start 260.226048 -255.22428)
		(end 260.226048 -252.91288)
		(width 0.18288)
		(layer "In6.Cu")
		(net "M_D_CPU0_SA_RSP<0>")
	)
	(segment
		(start 325.382382 -257.833114)
		(end 325.160132 -258.055364)
		(width 0.18288)
		(layer "In6.Cu")
		(net "M_D_CPU0_SA_RSP<0>")
	)
	(segment
		(start 255.882648 -245.369334)
		(end 257.185414 -244.066568)
		(width 0.18288)
		(layer "In6.Cu")
		(net "M_D_CPU0_SA_RSP<0>")
	)
	(segment
		(start 331.50937 -256.926588)
		(end 331.419962 -256.83718)
		(width 0.088646)
		(layer "In6.Cu")
		(net "M_D_CPU0_SA_RSP<0>")
	)
	(segment
		(start 262.834882 -257.833114)
		(end 260.226048 -255.22428)
		(width 0.18288)
		(layer "In6.Cu")
		(net "M_D_CPU0_SA_RSP<0>")
	)
	(segment
		(start 326.163178 -257.833114)
		(end 325.382382 -257.833114)
		(width 0.18288)
		(layer "In6.Cu")
		(net "M_D_CPU0_SA_RSP<0>")
	)
	(segment
		(start 325.160132 -258.055364)
		(end 319.291716 -258.055364)
		(width 0.18288)
		(layer "In6.Cu")
		(net "M_D_CPU0_SA_RSP<0>")
	)
	(segment
		(start 257.025648 -250.72848)
		(end 255.882648 -249.58548)
		(width 0.18288)
		(layer "In6.Cu")
		(net "M_D_CPU0_SA_RSP<0>")
	)
	(segment
		(start 314.415424 -257.83286)
		(end 314.41517 -257.833114)
		(width 0.18288)
		(layer "In6.Cu")
		(net "M_D_CPU0_SA_RSP<0>")
	)
	(segment
		(start 344.02649 -257.175254)
		(end 344.083894 -257.11785)
		(width 0.088646)
		(layer "In6.Cu")
		(net "M_D_CPU0_SA_RSP<0>")
	)
	(segment
		(start 328.567796 -256.83718)
		(end 326.163178 -257.833114)
		(width 0.18288)
		(layer "In6.Cu")
		(net "M_D_CPU0_SA_RSP<0>")
	)
	(segment
		(start 314.41517 -257.833114)
		(end 262.834882 -257.833114)
		(width 0.18288)
		(layer "In6.Cu")
		(net "M_D_CPU0_SA_RSP<0>")
	)
	(segment
		(start 340.152228 -256.856992)
		(end 340.141814 -256.850896)
		(width 0.088646)
		(layer "In6.Cu")
		(net "M_D_CPU0_SA_RSP<0>")
	)
	(segment
		(start 255.882648 -249.58548)
		(end 255.882648 -245.369334)
		(width 0.18288)
		(layer "In6.Cu")
		(net "M_D_CPU0_SA_RSP<0>")
	)
	(segment
		(start 343.909904 -256.855976)
		(end 343.901014 -256.850896)
		(width 0.088646)
		(layer "In6.Cu")
		(net "M_D_CPU0_SA_RSP<0>")
	)
	(segment
		(start 341.091774 -256.856992)
		(end 341.08136 -256.850896)
		(width 0.088646)
		(layer "In6.Cu")
		(net "M_D_CPU0_SA_RSP<0>")
	)
	(segment
		(start 339.212174 -256.856992)
		(end 339.20176 -256.850896)
		(width 0.088646)
		(layer "In6.Cu")
		(net "M_D_CPU0_SA_RSP<0>")
	)
	(segment
		(start 330.982828 -256.83718)
		(end 328.567796 -256.83718)
		(width 0.18288)
		(layer "In6.Cu")
		(net "M_D_CPU0_SA_RSP<0>")
	)
	(segment
		(start 260.226048 -252.91288)
		(end 258.041648 -250.72848)
		(width 0.18288)
		(layer "In6.Cu")
		(net "M_D_CPU0_SA_RSP<0>")
	)
	(segment
		(start 331.966062 -256.926588)
		(end 331.50937 -256.926588)
		(width 0.088646)
		(layer "In6.Cu")
		(net "M_D_CPU0_SA_RSP<0>")
	)
	(segment
		(start 319.069212 -257.83286)
		(end 314.415424 -257.83286)
		(width 0.18288)
		(layer "In6.Cu")
		(net "M_D_CPU0_SA_RSP<0>")
	)
	(segment
		(start 331.419962 -256.83718)
		(end 330.982828 -256.83718)
		(width 0.088646)
		(layer "In6.Cu")
		(net "M_D_CPU0_SA_RSP<0>")
	)
	(arc
		(start 338.26196 -256.850896)
		(mid 338.074762 -256.800753)
		(end 337.887564 -256.850896)
		(width 0.088646)
		(layer "In6.Cu")
		(net "M_D_CPU0_SA_RSP<0>")
	)
	(arc
		(start 337.887564 -256.850896)
		(mid 337.604862 -256.926672)
		(end 337.32216 -256.850896)
		(width 0.088646)
		(layer "In6.Cu")
		(net "M_D_CPU0_SA_RSP<0>")
	)
	(arc
		(start 343.526618 -256.850896)
		(mid 343.252419 -256.926731)
		(end 342.975946 -256.859532)
		(width 0.088646)
		(layer "In6.Cu")
		(net "M_D_CPU0_SA_RSP<0>")
	)
	(arc
		(start 336.947764 -256.850896)
		(mid 336.665062 -256.926672)
		(end 336.38236 -256.850896)
		(width 0.088646)
		(layer "In6.Cu")
		(net "M_D_CPU0_SA_RSP<0>")
	)
	(arc
		(start 340.141814 -256.850896)
		(mid 339.954616 -256.800753)
		(end 339.767418 -256.850896)
		(width 0.088646)
		(layer "In6.Cu")
		(net "M_D_CPU0_SA_RSP<0>")
	)
	(arc
		(start 338.827364 -256.850896)
		(mid 338.544662 -256.926672)
		(end 338.26196 -256.850896)
		(width 0.088646)
		(layer "In6.Cu")
		(net "M_D_CPU0_SA_RSP<0>")
	)
	(arc
		(start 342.961214 -256.850896)
		(mid 342.774016 -256.800753)
		(end 342.586818 -256.850896)
		(width 0.088646)
		(layer "In6.Cu")
		(net "M_D_CPU0_SA_RSP<0>")
	)
	(arc
		(start 335.068164 -256.850896)
		(mid 334.785462 -256.926672)
		(end 334.50276 -256.850896)
		(width 0.088646)
		(layer "In6.Cu")
		(net "M_D_CPU0_SA_RSP<0>")
	)
	(arc
		(start 339.767418 -256.850896)
		(mid 339.490605 -256.926766)
		(end 339.212174 -256.856992)
		(width 0.088646)
		(layer "In6.Cu")
		(net "M_D_CPU0_SA_RSP<0>")
	)
	(arc
		(start 344.083894 -257.11785)
		(mid 344.025738 -256.967737)
		(end 343.909904 -256.855976)
		(width 0.088646)
		(layer "In6.Cu")
		(net "M_D_CPU0_SA_RSP<0>")
	)
	(arc
		(start 332.248764 -256.850896)
		(mid 332.112395 -256.907338)
		(end 331.966062 -256.926588)
		(width 0.088646)
		(layer "In6.Cu")
		(net "M_D_CPU0_SA_RSP<0>")
	)
	(arc
		(start 336.38236 -256.850896)
		(mid 336.195162 -256.800753)
		(end 336.007964 -256.850896)
		(width 0.088646)
		(layer "In6.Cu")
		(net "M_D_CPU0_SA_RSP<0>")
	)
	(arc
		(start 333.56296 -256.850896)
		(mid 333.375762 -256.800753)
		(end 333.188564 -256.850896)
		(width 0.088646)
		(layer "In6.Cu")
		(net "M_D_CPU0_SA_RSP<0>")
	)
	(arc
		(start 334.50276 -256.850896)
		(mid 334.315562 -256.800753)
		(end 334.128364 -256.850896)
		(width 0.088646)
		(layer "In6.Cu")
		(net "M_D_CPU0_SA_RSP<0>")
	)
	(arc
		(start 343.901014 -256.850896)
		(mid 343.713816 -256.800753)
		(end 343.526618 -256.850896)
		(width 0.088646)
		(layer "In6.Cu")
		(net "M_D_CPU0_SA_RSP<0>")
	)
	(arc
		(start 339.20176 -256.850896)
		(mid 339.014562 -256.800753)
		(end 338.827364 -256.850896)
		(width 0.088646)
		(layer "In6.Cu")
		(net "M_D_CPU0_SA_RSP<0>")
	)
	(arc
		(start 333.188564 -256.850896)
		(mid 332.905862 -256.926672)
		(end 332.62316 -256.850896)
		(width 0.088646)
		(layer "In6.Cu")
		(net "M_D_CPU0_SA_RSP<0>")
	)
	(arc
		(start 342.021414 -256.850896)
		(mid 341.834216 -256.800753)
		(end 341.647018 -256.850896)
		(width 0.088646)
		(layer "In6.Cu")
		(net "M_D_CPU0_SA_RSP<0>")
	)
	(arc
		(start 342.586818 -256.850896)
		(mid 342.304116 -256.926672)
		(end 342.021414 -256.850896)
		(width 0.088646)
		(layer "In6.Cu")
		(net "M_D_CPU0_SA_RSP<0>")
	)
	(arc
		(start 332.62316 -256.850896)
		(mid 332.435962 -256.800753)
		(end 332.248764 -256.850896)
		(width 0.088646)
		(layer "In6.Cu")
		(net "M_D_CPU0_SA_RSP<0>")
	)
	(arc
		(start 334.128364 -256.850896)
		(mid 333.845662 -256.926672)
		(end 333.56296 -256.850896)
		(width 0.088646)
		(layer "In6.Cu")
		(net "M_D_CPU0_SA_RSP<0>")
	)
	(arc
		(start 341.647018 -256.850896)
		(mid 341.370205 -256.926766)
		(end 341.091774 -256.856992)
		(width 0.088646)
		(layer "In6.Cu")
		(net "M_D_CPU0_SA_RSP<0>")
	)
	(arc
		(start 336.007964 -256.850896)
		(mid 335.725262 -256.926672)
		(end 335.44256 -256.850896)
		(width 0.088646)
		(layer "In6.Cu")
		(net "M_D_CPU0_SA_RSP<0>")
	)
	(arc
		(start 335.44256 -256.850896)
		(mid 335.255362 -256.800753)
		(end 335.068164 -256.850896)
		(width 0.088646)
		(layer "In6.Cu")
		(net "M_D_CPU0_SA_RSP<0>")
	)
	(arc
		(start 341.08136 -256.850896)
		(mid 340.894162 -256.800753)
		(end 340.706964 -256.850896)
		(width 0.088646)
		(layer "In6.Cu")
		(net "M_D_CPU0_SA_RSP<0>")
	)
	(arc
		(start 340.706964 -256.850896)
		(mid 340.430405 -256.926639)
		(end 340.152228 -256.856992)
		(width 0.088646)
		(layer "In6.Cu")
		(net "M_D_CPU0_SA_RSP<0>")
	)
	(arc
		(start 337.32216 -256.850896)
		(mid 337.134962 -256.800753)
		(end 336.947764 -256.850896)
		(width 0.088646)
		(layer "In6.Cu")
		(net "M_D_CPU0_SA_RSP<0>")
	)
	(segment
		(start 261.917942 -259.366766)
		(end 261.493 -258.941824)
		(width 0.20066)
		(layer "F.Cu")
		(net "M_D_CPU0_SA_PAR")
	)
	(segment
		(start 258.081526 -259.60578)
		(end 257.65379 -259.60578)
		(width 0.20066)
		(layer "F.Cu")
		(net "M_D_CPU0_SA_PAR")
	)
	(segment
		(start 261.493 -258.941824)
		(end 261.381494 -258.941824)
		(width 0.20066)
		(layer "F.Cu")
		(net "M_D_CPU0_SA_PAR")
	)
	(segment
		(start 261.381494 -258.941824)
		(end 261.050786 -258.941824)
		(width 0.101854)
		(layer "F.Cu")
		(net "M_D_CPU0_SA_PAR")
	)
	(segment
		(start 264.729214 -259.366766)
		(end 263.624314 -259.366766)
		(width 0.20066)
		(layer "F.Cu")
		(net "M_D_CPU0_SA_PAR")
	)
	(segment
		(start 261.050786 -258.941824)
		(end 259.07873 -258.941824)
		(width 0.1016)
		(layer "F.Cu")
		(net "M_D_CPU0_SA_PAR")
	)
	(segment
		(start 259.056378 -258.95554)
		(end 258.425442 -258.95554)
		(width 0.20066)
		(layer "F.Cu")
		(net "M_D_CPU0_SA_PAR")
	)
	(segment
		(start 259.07873 -258.941824)
		(end 259.065014 -258.95554)
		(width 0.101854)
		(layer "F.Cu")
		(net "M_D_CPU0_SA_PAR")
	)
	(segment
		(start 348.30258 -249.342148)
		(end 348.302834 -249.341894)
		(width 0.20066)
		(layer "F.Cu")
		(net "M_D_CPU0_SA_PAR")
	)
	(segment
		(start 258.28498 -259.095494)
		(end 258.28498 -259.402326)
		(width 0.20066)
		(layer "F.Cu")
		(net "M_D_CPU0_SA_PAR")
	)
	(segment
		(start 259.065014 -258.95554)
		(end 259.056378 -258.95554)
		(width 0.101854)
		(layer "F.Cu")
		(net "M_D_CPU0_SA_PAR")
	)
	(segment
		(start 348.302834 -249.341894)
		(end 348.302834 -248.806208)
		(width 0.20066)
		(layer "F.Cu")
		(net "M_D_CPU0_SA_PAR")
	)
	(segment
		(start 263.624314 -259.366766)
		(end 261.917942 -259.366766)
		(width 0.20066)
		(layer "F.Cu")
		(net "M_D_CPU0_SA_PAR")
	)
	(segment
		(start 257.65379 -259.60578)
		(end 257.414776 -259.366766)
		(width 0.20066)
		(layer "F.Cu")
		(net "M_D_CPU0_SA_PAR")
	)
	(segment
		(start 257.414776 -259.366766)
		(end 256.080514 -259.366766)
		(width 0.20066)
		(layer "F.Cu")
		(net "M_D_CPU0_SA_PAR")
	)
	(segment
		(start 258.28498 -259.402326)
		(end 258.081526 -259.60578)
		(width 0.20066)
		(layer "F.Cu")
		(net "M_D_CPU0_SA_PAR")
	)
	(segment
		(start 258.425442 -258.95554)
		(end 258.425188 -258.955286)
		(width 0.20066)
		(layer "F.Cu")
		(net "M_D_CPU0_SA_PAR")
	)
	(segment
		(start 258.425188 -258.955286)
		(end 258.28498 -259.095494)
		(width 0.20066)
		(layer "F.Cu")
		(net "M_D_CPU0_SA_PAR")
	)
	(segment
		(start 323.48424 -255.58115)
		(end 322.872862 -254.969772)
		(width 0.18288)
		(layer "In11.Cu")
		(net "M_D_CPU0_SA_PAR")
	)
	(segment
		(start 301.566072 -257.052826)
		(end 301.079154 -256.565908)
		(width 0.18288)
		(layer "In11.Cu")
		(net "M_D_CPU0_SA_PAR")
	)
	(segment
		(start 332.760828 -253.541784)
		(end 332.388972 -253.91364)
		(width 0.18288)
		(layer "In11.Cu")
		(net "M_D_CPU0_SA_PAR")
	)
	(segment
		(start 305.485292 -257.052826)
		(end 301.566072 -257.052826)
		(width 0.18288)
		(layer "In11.Cu")
		(net "M_D_CPU0_SA_PAR")
	)
	(segment
		(start 274.878038 -257.052826)
		(end 274.584668 -257.052826)
		(width 0.18288)
		(layer "In11.Cu")
		(net "M_D_CPU0_SA_PAR")
	)
	(segment
		(start 267.807694 -260.641846)
		(end 265.111738 -259.525262)
		(width 0.18288)
		(layer "In11.Cu")
		(net "M_D_CPU0_SA_PAR")
	)
	(segment
		(start 347.10751 -252.721364)
		(end 343.089992 -252.721364)
		(width 0.088646)
		(layer "In11.Cu")
		(net "M_D_CPU0_SA_PAR")
	)
	(segment
		(start 282.972764 -256.565908)
		(end 282.485846 -257.052826)
		(width 0.18288)
		(layer "In11.Cu")
		(net "M_D_CPU0_SA_PAR")
	)
	(segment
		(start 282.485846 -257.052826)
		(end 279.068784 -257.052826)
		(width 0.18288)
		(layer "In11.Cu")
		(net "M_D_CPU0_SA_PAR")
	)
	(segment
		(start 270.05915 -259.61213)
		(end 269.640304 -260.030976)
		(width 0.18288)
		(layer "In11.Cu")
		(net "M_D_CPU0_SA_PAR")
	)
	(segment
		(start 271.632934 -258.275582)
		(end 270.296386 -259.61213)
		(width 0.18288)
		(layer "In11.Cu")
		(net "M_D_CPU0_SA_PAR")
	)
	(segment
		(start 279.068784 -257.052826)
		(end 278.57196 -256.556002)
		(width 0.18288)
		(layer "In11.Cu")
		(net "M_D_CPU0_SA_PAR")
	)
	(segment
		(start 349.14713 -250.681744)
		(end 347.10751 -252.721364)
		(width 0.088646)
		(layer "In11.Cu")
		(net "M_D_CPU0_SA_PAR")
	)
	(segment
		(start 274.584668 -257.052826)
		(end 271.632934 -258.275582)
		(width 0.18288)
		(layer "In11.Cu")
		(net "M_D_CPU0_SA_PAR")
	)
	(segment
		(start 334.2513 -253.541784)
		(end 332.760828 -253.541784)
		(width 0.18288)
		(layer "In11.Cu")
		(net "M_D_CPU0_SA_PAR")
	)
	(segment
		(start 343.089992 -252.721364)
		(end 342.888824 -252.922532)
		(width 0.088646)
		(layer "In11.Cu")
		(net "M_D_CPU0_SA_PAR")
	)
	(segment
		(start 269.640304 -260.030976)
		(end 269.640304 -260.138672)
		(width 0.18288)
		(layer "In11.Cu")
		(net "M_D_CPU0_SA_PAR")
	)
	(segment
		(start 275.374862 -256.556002)
		(end 274.878038 -257.052826)
		(width 0.18288)
		(layer "In11.Cu")
		(net "M_D_CPU0_SA_PAR")
	)
	(segment
		(start 290.444682 -256.553462)
		(end 289.945318 -257.052826)
		(width 0.18288)
		(layer "In11.Cu")
		(net "M_D_CPU0_SA_PAR")
	)
	(segment
		(start 294.009572 -256.93497)
		(end 293.628064 -256.553462)
		(width 0.18288)
		(layer "In11.Cu")
		(net "M_D_CPU0_SA_PAR")
	)
	(segment
		(start 334.870552 -252.922532)
		(end 334.2513 -253.541784)
		(width 0.18288)
		(layer "In11.Cu")
		(net "M_D_CPU0_SA_PAR")
	)
	(segment
		(start 311.808368 -256.265426)
		(end 307.386482 -256.265426)
		(width 0.18288)
		(layer "In11.Cu")
		(net "M_D_CPU0_SA_PAR")
	)
	(segment
		(start 297.948604 -256.565908)
		(end 297.579542 -256.93497)
		(width 0.18288)
		(layer "In11.Cu")
		(net "M_D_CPU0_SA_PAR")
	)
	(segment
		(start 348.67723 -248.797572)
		(end 348.67723 -248.816114)
		(width 0.088646)
		(layer "In11.Cu")
		(net "M_D_CPU0_SA_PAR")
	)
	(segment
		(start 322.872862 -254.969772)
		(end 314.936124 -254.969772)
		(width 0.18288)
		(layer "In11.Cu")
		(net "M_D_CPU0_SA_PAR")
	)
	(segment
		(start 342.888824 -252.922532)
		(end 342.261698 -252.922532)
		(width 0.088646)
		(layer "In11.Cu")
		(net "M_D_CPU0_SA_PAR")
	)
	(segment
		(start 270.296386 -259.61213)
		(end 270.05915 -259.61213)
		(width 0.18288)
		(layer "In11.Cu")
		(net "M_D_CPU0_SA_PAR")
	)
	(segment
		(start 293.628064 -256.553462)
		(end 290.444682 -256.553462)
		(width 0.18288)
		(layer "In11.Cu")
		(net "M_D_CPU0_SA_PAR")
	)
	(segment
		(start 332.388972 -253.91364)
		(end 329.63485 -253.91364)
		(width 0.18288)
		(layer "In11.Cu")
		(net "M_D_CPU0_SA_PAR")
	)
	(segment
		(start 269.640304 -260.138672)
		(end 269.13713 -260.641846)
		(width 0.18288)
		(layer "In11.Cu")
		(net "M_D_CPU0_SA_PAR")
	)
	(segment
		(start 348.14637 -248.53519)
		(end 348.167452 -248.457212)
		(width 0.088646)
		(layer "In11.Cu")
		(net "M_D_CPU0_SA_PAR")
	)
	(segment
		(start 307.386482 -256.265426)
		(end 305.485292 -257.052826)
		(width 0.18288)
		(layer "In11.Cu")
		(net "M_D_CPU0_SA_PAR")
	)
	(segment
		(start 342.261698 -252.922532)
		(end 334.870552 -252.922532)
		(width 0.18288)
		(layer "In11.Cu")
		(net "M_D_CPU0_SA_PAR")
	)
	(segment
		(start 289.945318 -257.052826)
		(end 286.632904 -257.052826)
		(width 0.18288)
		(layer "In11.Cu")
		(net "M_D_CPU0_SA_PAR")
	)
	(segment
		(start 297.579542 -256.93497)
		(end 294.009572 -256.93497)
		(width 0.18288)
		(layer "In11.Cu")
		(net "M_D_CPU0_SA_PAR")
	)
	(segment
		(start 327.96734 -255.58115)
		(end 323.48424 -255.58115)
		(width 0.18288)
		(layer "In11.Cu")
		(net "M_D_CPU0_SA_PAR")
	)
	(segment
		(start 286.632904 -257.052826)
		(end 286.145986 -256.565908)
		(width 0.18288)
		(layer "In11.Cu")
		(net "M_D_CPU0_SA_PAR")
	)
	(segment
		(start 348.959678 -249.295666)
		(end 348.968568 -249.300746)
		(width 0.088646)
		(layer "In11.Cu")
		(net "M_D_CPU0_SA_PAR")
	)
	(segment
		(start 269.13713 -260.641846)
		(end 267.807694 -260.641846)
		(width 0.18288)
		(layer "In11.Cu")
		(net "M_D_CPU0_SA_PAR")
	)
	(segment
		(start 265.111738 -259.525262)
		(end 264.729214 -259.366766)
		(width 0.18288)
		(layer "In11.Cu")
		(net "M_D_CPU0_SA_PAR")
	)
	(segment
		(start 329.63485 -253.91364)
		(end 327.96734 -255.58115)
		(width 0.18288)
		(layer "In11.Cu")
		(net "M_D_CPU0_SA_PAR")
	)
	(segment
		(start 301.079154 -256.565908)
		(end 297.948604 -256.565908)
		(width 0.18288)
		(layer "In11.Cu")
		(net "M_D_CPU0_SA_PAR")
	)
	(segment
		(start 314.936124 -254.969772)
		(end 311.808368 -256.265426)
		(width 0.18288)
		(layer "In11.Cu")
		(net "M_D_CPU0_SA_PAR")
	)
	(segment
		(start 286.145986 -256.565908)
		(end 282.972764 -256.565908)
		(width 0.18288)
		(layer "In11.Cu")
		(net "M_D_CPU0_SA_PAR")
	)
	(segment
		(start 349.14713 -249.620024)
		(end 349.14713 -250.681744)
		(width 0.088646)
		(layer "In11.Cu")
		(net "M_D_CPU0_SA_PAR")
	)
	(segment
		(start 348.302834 -248.806208)
		(end 348.14637 -248.53519)
		(width 0.088646)
		(layer "In11.Cu")
		(net "M_D_CPU0_SA_PAR")
	)
	(segment
		(start 278.57196 -256.556002)
		(end 275.374862 -256.556002)
		(width 0.18288)
		(layer "In11.Cu")
		(net "M_D_CPU0_SA_PAR")
	)
	(arc
		(start 348.67723 -248.816114)
		(mid 348.755341 -249.093063)
		(end 348.959678 -249.295666)
		(width 0.088646)
		(layer "In11.Cu")
		(net "M_D_CPU0_SA_PAR")
	)
	(arc
		(start 348.167452 -248.457212)
		(mid 348.331548 -248.432865)
		(end 348.490032 -248.48185)
		(width 0.088646)
		(layer "In11.Cu")
		(net "M_D_CPU0_SA_PAR")
	)
	(arc
		(start 348.490032 -248.48185)
		(mid 348.624965 -248.615204)
		(end 348.67723 -248.797572)
		(width 0.088646)
		(layer "In11.Cu")
		(net "M_D_CPU0_SA_PAR")
	)
	(arc
		(start 348.968568 -249.300746)
		(mid 349.099482 -249.437106)
		(end 349.14713 -249.620024)
		(width 0.088646)
		(layer "In11.Cu")
		(net "M_D_CPU0_SA_PAR")
	)
	(segment
		(start 266.973304 -274.077938)
		(end 266.368784 -274.077938)
		(width 0.20066)
		(layer "F.Cu")
		(net "M_D_CPU0_SA_DQS_DP<9>")
	)
	(segment
		(start 260.655054 -273.816572)
		(end 260.180582 -273.816572)
		(width 0.20066)
		(layer "F.Cu")
		(net "M_D_CPU0_SA_DQS_DP<9>")
	)
	(segment
		(start 262.033258 -273.655536)
		(end 261.673086 -273.655536)
		(width 0.20066)
		(layer "F.Cu")
		(net "M_D_CPU0_SA_DQS_DP<9>")
	)
	(segment
		(start 265.732768 -273.652996)
		(end 265.227816 -273.652996)
		(width 0.20066)
		(layer "F.Cu")
		(net "M_D_CPU0_SA_DQS_DP<9>")
	)
	(segment
		(start 261.250684 -274.077938)
		(end 260.91642 -274.077938)
		(width 0.20066)
		(layer "F.Cu")
		(net "M_D_CPU0_SA_DQS_DP<9>")
	)
	(segment
		(start 262.302752 -273.386042)
		(end 262.033258 -273.655536)
		(width 0.20066)
		(layer "F.Cu")
		(net "M_D_CPU0_SA_DQS_DP<9>")
	)
	(segment
		(start 262.50011 -273.386042)
		(end 262.302752 -273.386042)
		(width 0.20066)
		(layer "F.Cu")
		(net "M_D_CPU0_SA_DQS_DP<9>")
	)
	(segment
		(start 262.746998 -273.39163)
		(end 262.505698 -273.39163)
		(width 0.101854)
		(layer "F.Cu")
		(net "M_D_CPU0_SA_DQS_DP<9>")
	)
	(segment
		(start 261.673086 -273.655536)
		(end 261.250684 -274.077938)
		(width 0.20066)
		(layer "F.Cu")
		(net "M_D_CPU0_SA_DQS_DP<9>")
	)
	(segment
		(start 264.966704 -273.391884)
		(end 264.825226 -273.391884)
		(width 0.20066)
		(layer "F.Cu")
		(net "M_D_CPU0_SA_DQS_DP<9>")
	)
	(segment
		(start 265.227816 -273.652996)
		(end 264.966704 -273.391884)
		(width 0.20066)
		(layer "F.Cu")
		(net "M_D_CPU0_SA_DQS_DP<9>")
	)
	(segment
		(start 264.825226 -273.391884)
		(end 264.824972 -273.39163)
		(width 0.1016)
		(layer "F.Cu")
		(net "M_D_CPU0_SA_DQS_DP<9>")
	)
	(segment
		(start 260.91642 -274.077938)
		(end 260.655054 -273.816572)
		(width 0.20066)
		(layer "F.Cu")
		(net "M_D_CPU0_SA_DQS_DP<9>")
	)
	(segment
		(start 348.882716 -262.336534)
		(end 348.882716 -262.87222)
		(width 0.20066)
		(layer "F.Cu")
		(net "M_D_CPU0_SA_DQS_DP<9>")
	)
	(segment
		(start 264.824972 -273.39163)
		(end 262.746998 -273.39163)
		(width 0.1016)
		(layer "F.Cu")
		(net "M_D_CPU0_SA_DQS_DP<9>")
	)
	(segment
		(start 348.882716 -262.87222)
		(end 348.882462 -262.872474)
		(width 0.20066)
		(layer "F.Cu")
		(net "M_D_CPU0_SA_DQS_DP<9>")
	)
	(segment
		(start 267.23467 -273.816572)
		(end 266.973304 -274.077938)
		(width 0.20066)
		(layer "F.Cu")
		(net "M_D_CPU0_SA_DQS_DP<9>")
	)
	(segment
		(start 268.829282 -273.816572)
		(end 267.724382 -273.816572)
		(width 0.20066)
		(layer "F.Cu")
		(net "M_D_CPU0_SA_DQS_DP<9>")
	)
	(segment
		(start 262.505698 -273.39163)
		(end 262.50011 -273.386042)
		(width 0.101854)
		(layer "F.Cu")
		(net "M_D_CPU0_SA_DQS_DP<9>")
	)
	(segment
		(start 267.724382 -273.816572)
		(end 267.23467 -273.816572)
		(width 0.20066)
		(layer "F.Cu")
		(net "M_D_CPU0_SA_DQS_DP<9>")
	)
	(segment
		(start 266.368784 -274.077938)
		(end 265.732768 -273.652996)
		(width 0.20066)
		(layer "F.Cu")
		(net "M_D_CPU0_SA_DQS_DP<9>")
	)
	(segment
		(start 343.532206 -262.386318)
		(end 343.520522 -262.379714)
		(width 0.088646)
		(layer "In11.Cu")
		(net "M_D_CPU0_SA_DQS_DP<9>")
	)
	(segment
		(start 323.00037 -262.74903)
		(end 315.39688 -270.35252)
		(width 0.18288)
		(layer "In11.Cu")
		(net "M_D_CPU0_SA_DQS_DP<9>")
	)
	(segment
		(start 291.85108 -272.039588)
		(end 288.629852 -272.039588)
		(width 0.18288)
		(layer "In11.Cu")
		(net "M_D_CPU0_SA_DQS_DP<9>")
	)
	(segment
		(start 331.519276 -262.54964)
		(end 331.260196 -262.808974)
		(width 0.088646)
		(layer "In11.Cu")
		(net "M_D_CPU0_SA_DQS_DP<9>")
	)
	(segment
		(start 294.452548 -271.952212)
		(end 293.864538 -271.952212)
		(width 0.18288)
		(layer "In11.Cu")
		(net "M_D_CPU0_SA_DQS_DP<9>")
	)
	(segment
		(start 299.192442 -270.840962)
		(end 298.813982 -270.840962)
		(width 0.18288)
		(layer "In11.Cu")
		(net "M_D_CPU0_SA_DQS_DP<9>")
	)
	(segment
		(start 283.406088 -271.171416)
		(end 282.654756 -271.171416)
		(width 0.18288)
		(layer "In11.Cu")
		(net "M_D_CPU0_SA_DQS_DP<9>")
	)
	(segment
		(start 339.773006 -262.386318)
		(end 339.761322 -262.379714)
		(width 0.088646)
		(layer "In11.Cu")
		(net "M_D_CPU0_SA_DQS_DP<9>")
	)
	(segment
		(start 300.58614 -271.106392)
		(end 299.457872 -271.106392)
		(width 0.18288)
		(layer "In11.Cu")
		(net "M_D_CPU0_SA_DQS_DP<9>")
	)
	(segment
		(start 292.431724 -272.620232)
		(end 291.85108 -272.039588)
		(width 0.18288)
		(layer "In11.Cu")
		(net "M_D_CPU0_SA_DQS_DP<9>")
	)
	(segment
		(start 348.882462 -262.872474)
		(end 348.569788 -262.872474)
		(width 0.088646)
		(layer "In11.Cu")
		(net "M_D_CPU0_SA_DQS_DP<9>")
	)
	(segment
		(start 282.654756 -271.171416)
		(end 281.851354 -271.974818)
		(width 0.18288)
		(layer "In11.Cu")
		(net "M_D_CPU0_SA_DQS_DP<9>")
	)
	(segment
		(start 276.840188 -272.22323)
		(end 273.781774 -272.22323)
		(width 0.18288)
		(layer "In11.Cu")
		(net "M_D_CPU0_SA_DQS_DP<9>")
	)
	(segment
		(start 281.851354 -271.974818)
		(end 280.289762 -271.974818)
		(width 0.18288)
		(layer "In11.Cu")
		(net "M_D_CPU0_SA_DQS_DP<9>")
	)
	(segment
		(start 288.629852 -272.039588)
		(end 287.956244 -271.36598)
		(width 0.18288)
		(layer "In11.Cu")
		(net "M_D_CPU0_SA_DQS_DP<9>")
	)
	(segment
		(start 340.712806 -262.386318)
		(end 340.701122 -262.379714)
		(width 0.088646)
		(layer "In11.Cu")
		(net "M_D_CPU0_SA_DQS_DP<9>")
	)
	(segment
		(start 331.037184 -262.808974)
		(end 330.97724 -262.74903)
		(width 0.088646)
		(layer "In11.Cu")
		(net "M_D_CPU0_SA_DQS_DP<9>")
	)
	(segment
		(start 297.708066 -271.106392)
		(end 297.205908 -271.608296)
		(width 0.18288)
		(layer "In11.Cu")
		(net "M_D_CPU0_SA_DQS_DP<9>")
	)
	(segment
		(start 298.813982 -270.840962)
		(end 298.548552 -271.106392)
		(width 0.18288)
		(layer "In11.Cu")
		(net "M_D_CPU0_SA_DQS_DP<9>")
	)
	(segment
		(start 297.205908 -271.608296)
		(end 296.348658 -271.963134)
		(width 0.18288)
		(layer "In11.Cu")
		(net "M_D_CPU0_SA_DQS_DP<9>")
	)
	(segment
		(start 303.178718 -271.371314)
		(end 300.851062 -271.371314)
		(width 0.18288)
		(layer "In11.Cu")
		(net "M_D_CPU0_SA_DQS_DP<9>")
	)
	(segment
		(start 269.537688 -274.068032)
		(end 269.080742 -274.068032)
		(width 0.18288)
		(layer "In11.Cu")
		(net "M_D_CPU0_SA_DQS_DP<9>")
	)
	(segment
		(start 344.472006 -262.386318)
		(end 344.460322 -262.379714)
		(width 0.088646)
		(layer "In11.Cu")
		(net "M_D_CPU0_SA_DQS_DP<9>")
	)
	(segment
		(start 304.026824 -270.523208)
		(end 303.178718 -271.371314)
		(width 0.18288)
		(layer "In11.Cu")
		(net "M_D_CPU0_SA_DQS_DP<9>")
	)
	(segment
		(start 306.924964 -270.523208)
		(end 304.026824 -270.523208)
		(width 0.18288)
		(layer "In11.Cu")
		(net "M_D_CPU0_SA_DQS_DP<9>")
	)
	(segment
		(start 279.371298 -271.945862)
		(end 278.843994 -271.945862)
		(width 0.18288)
		(layer "In11.Cu")
		(net "M_D_CPU0_SA_DQS_DP<9>")
	)
	(segment
		(start 269.080742 -274.068032)
		(end 268.829282 -273.816572)
		(width 0.18288)
		(layer "In11.Cu")
		(net "M_D_CPU0_SA_DQS_DP<9>")
	)
	(segment
		(start 307.371242 -270.969486)
		(end 306.924964 -270.523208)
		(width 0.18288)
		(layer "In11.Cu")
		(net "M_D_CPU0_SA_DQS_DP<9>")
	)
	(segment
		(start 342.592406 -262.386318)
		(end 342.580722 -262.379714)
		(width 0.088646)
		(layer "In11.Cu")
		(net "M_D_CPU0_SA_DQS_DP<9>")
	)
	(segment
		(start 278.843994 -271.945862)
		(end 278.18715 -272.602706)
		(width 0.18288)
		(layer "In11.Cu")
		(net "M_D_CPU0_SA_DQS_DP<9>")
	)
	(segment
		(start 315.39688 -270.35252)
		(end 311.21477 -270.35252)
		(width 0.18288)
		(layer "In11.Cu")
		(net "M_D_CPU0_SA_DQS_DP<9>")
	)
	(segment
		(start 341.652606 -262.386318)
		(end 341.640922 -262.379714)
		(width 0.088646)
		(layer "In11.Cu")
		(net "M_D_CPU0_SA_DQS_DP<9>")
	)
	(segment
		(start 285.618936 -271.36598)
		(end 285.37789 -271.124934)
		(width 0.18288)
		(layer "In11.Cu")
		(net "M_D_CPU0_SA_DQS_DP<9>")
	)
	(segment
		(start 345.411806 -262.386318)
		(end 345.400122 -262.379714)
		(width 0.088646)
		(layer "In11.Cu")
		(net "M_D_CPU0_SA_DQS_DP<9>")
	)
	(segment
		(start 299.457872 -271.106392)
		(end 299.192442 -270.840962)
		(width 0.18288)
		(layer "In11.Cu")
		(net "M_D_CPU0_SA_DQS_DP<9>")
	)
	(segment
		(start 293.864538 -271.952212)
		(end 293.196518 -272.620232)
		(width 0.18288)
		(layer "In11.Cu")
		(net "M_D_CPU0_SA_DQS_DP<9>")
	)
	(segment
		(start 279.626314 -271.690846)
		(end 279.371298 -271.945862)
		(width 0.18288)
		(layer "In11.Cu")
		(net "M_D_CPU0_SA_DQS_DP<9>")
	)
	(segment
		(start 283.736542 -270.840962)
		(end 283.406088 -271.171416)
		(width 0.18288)
		(layer "In11.Cu")
		(net "M_D_CPU0_SA_DQS_DP<9>")
	)
	(segment
		(start 272.933668 -273.071336)
		(end 271.858994 -273.071336)
		(width 0.18288)
		(layer "In11.Cu")
		(net "M_D_CPU0_SA_DQS_DP<9>")
	)
	(segment
		(start 296.348658 -271.963134)
		(end 295.367202 -271.963134)
		(width 0.18288)
		(layer "In11.Cu")
		(net "M_D_CPU0_SA_DQS_DP<9>")
	)
	(segment
		(start 347.291406 -262.386318)
		(end 347.279722 -262.379714)
		(width 0.088646)
		(layer "In11.Cu")
		(net "M_D_CPU0_SA_DQS_DP<9>")
	)
	(segment
		(start 300.851062 -271.371314)
		(end 300.58614 -271.106392)
		(width 0.18288)
		(layer "In11.Cu")
		(net "M_D_CPU0_SA_DQS_DP<9>")
	)
	(segment
		(start 293.196518 -272.620232)
		(end 292.431724 -272.620232)
		(width 0.18288)
		(layer "In11.Cu")
		(net "M_D_CPU0_SA_DQS_DP<9>")
	)
	(segment
		(start 332.239874 -262.410448)
		(end 332.145894 -262.384286)
		(width 0.088646)
		(layer "In11.Cu")
		(net "M_D_CPU0_SA_DQS_DP<9>")
	)
	(segment
		(start 280.00579 -271.690846)
		(end 279.626314 -271.690846)
		(width 0.18288)
		(layer "In11.Cu")
		(net "M_D_CPU0_SA_DQS_DP<9>")
	)
	(segment
		(start 284.104842 -270.840962)
		(end 283.736542 -270.840962)
		(width 0.18288)
		(layer "In11.Cu")
		(net "M_D_CPU0_SA_DQS_DP<9>")
	)
	(segment
		(start 330.97724 -262.74903)
		(end 323.00037 -262.74903)
		(width 0.18288)
		(layer "In11.Cu")
		(net "M_D_CPU0_SA_DQS_DP<9>")
	)
	(segment
		(start 346.351606 -262.386318)
		(end 346.339922 -262.379714)
		(width 0.088646)
		(layer "In11.Cu")
		(net "M_D_CPU0_SA_DQS_DP<9>")
	)
	(segment
		(start 295.367202 -271.963134)
		(end 295.094914 -271.690846)
		(width 0.18288)
		(layer "In11.Cu")
		(net "M_D_CPU0_SA_DQS_DP<9>")
	)
	(segment
		(start 337.891882 -262.385556)
		(end 337.887564 -262.383016)
		(width 0.088646)
		(layer "In11.Cu")
		(net "M_D_CPU0_SA_DQS_DP<9>")
	)
	(segment
		(start 284.388814 -271.124934)
		(end 284.104842 -270.840962)
		(width 0.18288)
		(layer "In11.Cu")
		(net "M_D_CPU0_SA_DQS_DP<9>")
	)
	(segment
		(start 310.597804 -270.969486)
		(end 307.371242 -270.969486)
		(width 0.18288)
		(layer "In11.Cu")
		(net "M_D_CPU0_SA_DQS_DP<9>")
	)
	(segment
		(start 336.392774 -262.37692)
		(end 336.38236 -262.383016)
		(width 0.088646)
		(layer "In11.Cu")
		(net "M_D_CPU0_SA_DQS_DP<9>")
	)
	(segment
		(start 348.569788 -262.872474)
		(end 348.504256 -262.806942)
		(width 0.088646)
		(layer "In11.Cu")
		(net "M_D_CPU0_SA_DQS_DP<9>")
	)
	(segment
		(start 278.18715 -272.602706)
		(end 277.219664 -272.602706)
		(width 0.18288)
		(layer "In11.Cu")
		(net "M_D_CPU0_SA_DQS_DP<9>")
	)
	(segment
		(start 280.289762 -271.974818)
		(end 280.00579 -271.690846)
		(width 0.18288)
		(layer "In11.Cu")
		(net "M_D_CPU0_SA_DQS_DP<9>")
	)
	(segment
		(start 338.833206 -262.386318)
		(end 338.821522 -262.379714)
		(width 0.088646)
		(layer "In11.Cu")
		(net "M_D_CPU0_SA_DQS_DP<9>")
	)
	(segment
		(start 298.548552 -271.106392)
		(end 297.708066 -271.106392)
		(width 0.18288)
		(layer "In11.Cu")
		(net "M_D_CPU0_SA_DQS_DP<9>")
	)
	(segment
		(start 271.858994 -273.071336)
		(end 270.506444 -274.423886)
		(width 0.18288)
		(layer "In11.Cu")
		(net "M_D_CPU0_SA_DQS_DP<9>")
	)
	(segment
		(start 294.713914 -271.690846)
		(end 294.452548 -271.952212)
		(width 0.18288)
		(layer "In11.Cu")
		(net "M_D_CPU0_SA_DQS_DP<9>")
	)
	(segment
		(start 269.893542 -274.423886)
		(end 269.537688 -274.068032)
		(width 0.18288)
		(layer "In11.Cu")
		(net "M_D_CPU0_SA_DQS_DP<9>")
	)
	(segment
		(start 295.094914 -271.690846)
		(end 294.713914 -271.690846)
		(width 0.18288)
		(layer "In11.Cu")
		(net "M_D_CPU0_SA_DQS_DP<9>")
	)
	(segment
		(start 287.956244 -271.36598)
		(end 285.618936 -271.36598)
		(width 0.18288)
		(layer "In11.Cu")
		(net "M_D_CPU0_SA_DQS_DP<9>")
	)
	(segment
		(start 273.781774 -272.22323)
		(end 272.933668 -273.071336)
		(width 0.18288)
		(layer "In11.Cu")
		(net "M_D_CPU0_SA_DQS_DP<9>")
	)
	(segment
		(start 331.260196 -262.808974)
		(end 331.037184 -262.808974)
		(width 0.088646)
		(layer "In11.Cu")
		(net "M_D_CPU0_SA_DQS_DP<9>")
	)
	(segment
		(start 285.37789 -271.124934)
		(end 284.388814 -271.124934)
		(width 0.18288)
		(layer "In11.Cu")
		(net "M_D_CPU0_SA_DQS_DP<9>")
	)
	(segment
		(start 270.506444 -274.423886)
		(end 269.893542 -274.423886)
		(width 0.18288)
		(layer "In11.Cu")
		(net "M_D_CPU0_SA_DQS_DP<9>")
	)
	(segment
		(start 277.219664 -272.602706)
		(end 276.840188 -272.22323)
		(width 0.18288)
		(layer "In11.Cu")
		(net "M_D_CPU0_SA_DQS_DP<9>")
	)
	(segment
		(start 311.21477 -270.35252)
		(end 310.597804 -270.969486)
		(width 0.18288)
		(layer "In11.Cu")
		(net "M_D_CPU0_SA_DQS_DP<9>")
	)
	(arc
		(start 347.279722 -262.379714)
		(mid 346.999617 -262.307272)
		(end 346.720414 -262.383016)
		(width 0.088646)
		(layer "In11.Cu")
		(net "M_D_CPU0_SA_DQS_DP<9>")
	)
	(arc
		(start 336.948018 -262.383016)
		(mid 336.671205 -262.307146)
		(end 336.392774 -262.37692)
		(width 0.088646)
		(layer "In11.Cu")
		(net "M_D_CPU0_SA_DQS_DP<9>")
	)
	(arc
		(start 340.141814 -262.383016)
		(mid 339.95786 -262.433145)
		(end 339.773006 -262.386318)
		(width 0.088646)
		(layer "In11.Cu")
		(net "M_D_CPU0_SA_DQS_DP<9>")
	)
	(arc
		(start 341.640922 -262.379714)
		(mid 341.360817 -262.307272)
		(end 341.081614 -262.383016)
		(width 0.088646)
		(layer "In11.Cu")
		(net "M_D_CPU0_SA_DQS_DP<9>")
	)
	(arc
		(start 343.520522 -262.379714)
		(mid 343.240417 -262.307272)
		(end 342.961214 -262.383016)
		(width 0.088646)
		(layer "In11.Cu")
		(net "M_D_CPU0_SA_DQS_DP<9>")
	)
	(arc
		(start 338.821522 -262.379714)
		(mid 338.541417 -262.307272)
		(end 338.262214 -262.383016)
		(width 0.088646)
		(layer "In11.Cu")
		(net "M_D_CPU0_SA_DQS_DP<9>")
	)
	(arc
		(start 334.128364 -262.383016)
		(mid 333.845662 -262.30724)
		(end 333.56296 -262.383016)
		(width 0.088646)
		(layer "In11.Cu")
		(net "M_D_CPU0_SA_DQS_DP<9>")
	)
	(arc
		(start 339.761322 -262.379714)
		(mid 339.481217 -262.307272)
		(end 339.202014 -262.383016)
		(width 0.088646)
		(layer "In11.Cu")
		(net "M_D_CPU0_SA_DQS_DP<9>")
	)
	(arc
		(start 345.780614 -262.383016)
		(mid 345.59666 -262.433145)
		(end 345.411806 -262.386318)
		(width 0.088646)
		(layer "In11.Cu")
		(net "M_D_CPU0_SA_DQS_DP<9>")
	)
	(arc
		(start 333.188564 -262.383016)
		(mid 332.920214 -262.307267)
		(end 332.648306 -262.369046)
		(width 0.088646)
		(layer "In11.Cu")
		(net "M_D_CPU0_SA_DQS_DP<9>")
	)
	(arc
		(start 336.38236 -262.383016)
		(mid 336.195162 -262.433159)
		(end 336.007964 -262.383016)
		(width 0.088646)
		(layer "In11.Cu")
		(net "M_D_CPU0_SA_DQS_DP<9>")
	)
	(arc
		(start 334.50276 -262.383016)
		(mid 334.315562 -262.433159)
		(end 334.128364 -262.383016)
		(width 0.088646)
		(layer "In11.Cu")
		(net "M_D_CPU0_SA_DQS_DP<9>")
	)
	(arc
		(start 335.44256 -262.383016)
		(mid 335.255362 -262.433159)
		(end 335.068164 -262.383016)
		(width 0.088646)
		(layer "In11.Cu")
		(net "M_D_CPU0_SA_DQS_DP<9>")
	)
	(arc
		(start 346.720414 -262.383016)
		(mid 346.53646 -262.433145)
		(end 346.351606 -262.386318)
		(width 0.088646)
		(layer "In11.Cu")
		(net "M_D_CPU0_SA_DQS_DP<9>")
	)
	(arc
		(start 342.580722 -262.379714)
		(mid 342.300617 -262.307272)
		(end 342.021414 -262.383016)
		(width 0.088646)
		(layer "In11.Cu")
		(net "M_D_CPU0_SA_DQS_DP<9>")
	)
	(arc
		(start 348.501462 -262.78586)
		(mid 348.187031 -262.362686)
		(end 347.660214 -262.383016)
		(width 0.088646)
		(layer "In11.Cu")
		(net "M_D_CPU0_SA_DQS_DP<9>")
	)
	(arc
		(start 346.339922 -262.379714)
		(mid 346.059817 -262.307272)
		(end 345.780614 -262.383016)
		(width 0.088646)
		(layer "In11.Cu")
		(net "M_D_CPU0_SA_DQS_DP<9>")
	)
	(arc
		(start 348.504256 -262.806942)
		(mid 348.502957 -262.796388)
		(end 348.501462 -262.78586)
		(width 0.088646)
		(layer "In11.Cu")
		(net "M_D_CPU0_SA_DQS_DP<9>")
	)
	(arc
		(start 343.901014 -262.383016)
		(mid 343.71706 -262.433145)
		(end 343.532206 -262.386318)
		(width 0.088646)
		(layer "In11.Cu")
		(net "M_D_CPU0_SA_DQS_DP<9>")
	)
	(arc
		(start 342.961214 -262.383016)
		(mid 342.77726 -262.433145)
		(end 342.592406 -262.386318)
		(width 0.088646)
		(layer "In11.Cu")
		(net "M_D_CPU0_SA_DQS_DP<9>")
	)
	(arc
		(start 344.840814 -262.383016)
		(mid 344.65686 -262.433145)
		(end 344.472006 -262.386318)
		(width 0.088646)
		(layer "In11.Cu")
		(net "M_D_CPU0_SA_DQS_DP<9>")
	)
	(arc
		(start 336.007964 -262.383016)
		(mid 335.725262 -262.30724)
		(end 335.44256 -262.383016)
		(width 0.088646)
		(layer "In11.Cu")
		(net "M_D_CPU0_SA_DQS_DP<9>")
	)
	(arc
		(start 344.460322 -262.379714)
		(mid 344.180217 -262.307272)
		(end 343.901014 -262.383016)
		(width 0.088646)
		(layer "In11.Cu")
		(net "M_D_CPU0_SA_DQS_DP<9>")
	)
	(arc
		(start 332.648306 -262.369046)
		(mid 332.447983 -262.428137)
		(end 332.239874 -262.410448)
		(width 0.088646)
		(layer "In11.Cu")
		(net "M_D_CPU0_SA_DQS_DP<9>")
	)
	(arc
		(start 332.145894 -262.384286)
		(mid 331.810267 -262.38232)
		(end 331.519276 -262.54964)
		(width 0.088646)
		(layer "In11.Cu")
		(net "M_D_CPU0_SA_DQS_DP<9>")
	)
	(arc
		(start 337.887564 -262.383016)
		(mid 337.605006 -262.307367)
		(end 337.322414 -262.383016)
		(width 0.088646)
		(layer "In11.Cu")
		(net "M_D_CPU0_SA_DQS_DP<9>")
	)
	(arc
		(start 339.202014 -262.383016)
		(mid 339.01806 -262.433145)
		(end 338.833206 -262.386318)
		(width 0.088646)
		(layer "In11.Cu")
		(net "M_D_CPU0_SA_DQS_DP<9>")
	)
	(arc
		(start 333.56296 -262.383016)
		(mid 333.375762 -262.433159)
		(end 333.188564 -262.383016)
		(width 0.088646)
		(layer "In11.Cu")
		(net "M_D_CPU0_SA_DQS_DP<9>")
	)
	(arc
		(start 337.322414 -262.383016)
		(mid 337.135216 -262.433159)
		(end 336.948018 -262.383016)
		(width 0.088646)
		(layer "In11.Cu")
		(net "M_D_CPU0_SA_DQS_DP<9>")
	)
	(arc
		(start 335.068164 -262.383016)
		(mid 334.785462 -262.30724)
		(end 334.50276 -262.383016)
		(width 0.088646)
		(layer "In11.Cu")
		(net "M_D_CPU0_SA_DQS_DP<9>")
	)
	(arc
		(start 338.262214 -262.383016)
		(mid 338.077377 -262.433277)
		(end 337.891882 -262.385556)
		(width 0.088646)
		(layer "In11.Cu")
		(net "M_D_CPU0_SA_DQS_DP<9>")
	)
	(arc
		(start 341.081614 -262.383016)
		(mid 340.89766 -262.433145)
		(end 340.712806 -262.386318)
		(width 0.088646)
		(layer "In11.Cu")
		(net "M_D_CPU0_SA_DQS_DP<9>")
	)
	(arc
		(start 342.021414 -262.383016)
		(mid 341.83746 -262.433145)
		(end 341.652606 -262.386318)
		(width 0.088646)
		(layer "In11.Cu")
		(net "M_D_CPU0_SA_DQS_DP<9>")
	)
	(arc
		(start 347.660214 -262.383016)
		(mid 347.47626 -262.433145)
		(end 347.291406 -262.386318)
		(width 0.088646)
		(layer "In11.Cu")
		(net "M_D_CPU0_SA_DQS_DP<9>")
	)
	(arc
		(start 340.701122 -262.379714)
		(mid 340.421017 -262.307272)
		(end 340.141814 -262.383016)
		(width 0.088646)
		(layer "In11.Cu")
		(net "M_D_CPU0_SA_DQS_DP<9>")
	)
	(arc
		(start 345.400122 -262.379714)
		(mid 345.120017 -262.307272)
		(end 344.840814 -262.383016)
		(width 0.088646)
		(layer "In11.Cu")
		(net "M_D_CPU0_SA_DQS_DP<9>")
	)
	(segment
		(start 264.824972 -282.741624)
		(end 262.746998 -282.741624)
		(width 0.1016)
		(layer "F.Cu")
		(net "M_D_CPU0_SA_DQS_DP<8>")
	)
	(segment
		(start 268.829282 -283.166566)
		(end 267.724382 -283.166566)
		(width 0.20066)
		(layer "F.Cu")
		(net "M_D_CPU0_SA_DQS_DP<8>")
	)
	(segment
		(start 266.973304 -283.427932)
		(end 266.368784 -283.427932)
		(width 0.20066)
		(layer "F.Cu")
		(net "M_D_CPU0_SA_DQS_DP<8>")
	)
	(segment
		(start 262.302752 -282.736036)
		(end 262.033258 -283.00553)
		(width 0.20066)
		(layer "F.Cu")
		(net "M_D_CPU0_SA_DQS_DP<8>")
	)
	(segment
		(start 262.505698 -282.741624)
		(end 262.50011 -282.736036)
		(width 0.101854)
		(layer "F.Cu")
		(net "M_D_CPU0_SA_DQS_DP<8>")
	)
	(segment
		(start 265.732768 -283.00299)
		(end 265.227816 -283.00299)
		(width 0.20066)
		(layer "F.Cu")
		(net "M_D_CPU0_SA_DQS_DP<8>")
	)
	(segment
		(start 267.724382 -283.166566)
		(end 267.23467 -283.166566)
		(width 0.20066)
		(layer "F.Cu")
		(net "M_D_CPU0_SA_DQS_DP<8>")
	)
	(segment
		(start 261.250684 -283.427932)
		(end 260.91642 -283.427932)
		(width 0.20066)
		(layer "F.Cu")
		(net "M_D_CPU0_SA_DQS_DP<8>")
	)
	(segment
		(start 267.23467 -283.166566)
		(end 266.973304 -283.427932)
		(width 0.20066)
		(layer "F.Cu")
		(net "M_D_CPU0_SA_DQS_DP<8>")
	)
	(segment
		(start 264.966704 -282.741878)
		(end 264.825226 -282.741878)
		(width 0.20066)
		(layer "F.Cu")
		(net "M_D_CPU0_SA_DQS_DP<8>")
	)
	(segment
		(start 262.50011 -282.736036)
		(end 262.302752 -282.736036)
		(width 0.20066)
		(layer "F.Cu")
		(net "M_D_CPU0_SA_DQS_DP<8>")
	)
	(segment
		(start 262.746998 -282.741624)
		(end 262.505698 -282.741624)
		(width 0.101854)
		(layer "F.Cu")
		(net "M_D_CPU0_SA_DQS_DP<8>")
	)
	(segment
		(start 348.882462 -267.220192)
		(end 348.882462 -267.755878)
		(width 0.20066)
		(layer "F.Cu")
		(net "M_D_CPU0_SA_DQS_DP<8>")
	)
	(segment
		(start 264.825226 -282.741878)
		(end 264.824972 -282.741624)
		(width 0.1016)
		(layer "F.Cu")
		(net "M_D_CPU0_SA_DQS_DP<8>")
	)
	(segment
		(start 260.91642 -283.427932)
		(end 260.655054 -283.166566)
		(width 0.20066)
		(layer "F.Cu")
		(net "M_D_CPU0_SA_DQS_DP<8>")
	)
	(segment
		(start 266.368784 -283.427932)
		(end 265.732768 -283.00299)
		(width 0.20066)
		(layer "F.Cu")
		(net "M_D_CPU0_SA_DQS_DP<8>")
	)
	(segment
		(start 348.882716 -267.219938)
		(end 348.882462 -267.220192)
		(width 0.20066)
		(layer "F.Cu")
		(net "M_D_CPU0_SA_DQS_DP<8>")
	)
	(segment
		(start 262.033258 -283.00553)
		(end 261.673086 -283.00553)
		(width 0.20066)
		(layer "F.Cu")
		(net "M_D_CPU0_SA_DQS_DP<8>")
	)
	(segment
		(start 261.673086 -283.00553)
		(end 261.250684 -283.427932)
		(width 0.20066)
		(layer "F.Cu")
		(net "M_D_CPU0_SA_DQS_DP<8>")
	)
	(segment
		(start 265.227816 -283.00299)
		(end 264.966704 -282.741878)
		(width 0.20066)
		(layer "F.Cu")
		(net "M_D_CPU0_SA_DQS_DP<8>")
	)
	(segment
		(start 260.655054 -283.166566)
		(end 260.180582 -283.166566)
		(width 0.20066)
		(layer "F.Cu")
		(net "M_D_CPU0_SA_DQS_DP<8>")
	)
	(segment
		(start 303.798732 -281.4193)
		(end 303.044098 -282.173934)
		(width 0.18288)
		(layer "In11.Cu")
		(net "M_D_CPU0_SA_DQS_DP<8>")
	)
	(segment
		(start 282.69565 -282.560776)
		(end 281.610308 -283.01061)
		(width 0.18288)
		(layer "In11.Cu")
		(net "M_D_CPU0_SA_DQS_DP<8>")
	)
	(segment
		(start 332.436216 -267.316966)
		(end 332.152244 -267.316966)
		(width 0.088646)
		(layer "In11.Cu")
		(net "M_D_CPU0_SA_DQS_DP<8>")
	)
	(segment
		(start 346.735146 -267.25753)
		(end 346.720414 -267.266166)
		(width 0.088646)
		(layer "In11.Cu")
		(net "M_D_CPU0_SA_DQS_DP<8>")
	)
	(segment
		(start 292.182804 -282.422346)
		(end 291.73297 -282.871926)
		(width 0.18288)
		(layer "In11.Cu")
		(net "M_D_CPU0_SA_DQS_DP<8>")
	)
	(segment
		(start 269.63497 -283.422852)
		(end 269.085568 -283.422852)
		(width 0.18288)
		(layer "In11.Cu")
		(net "M_D_CPU0_SA_DQS_DP<8>")
	)
	(segment
		(start 284.098746 -281.890724)
		(end 283.726382 -281.890724)
		(width 0.18288)
		(layer "In11.Cu")
		(net "M_D_CPU0_SA_DQS_DP<8>")
	)
	(segment
		(start 339.212174 -267.26007)
		(end 339.20176 -267.266166)
		(width 0.088646)
		(layer "In11.Cu")
		(net "M_D_CPU0_SA_DQS_DP<8>")
	)
	(segment
		(start 309.044594 -280.717498)
		(end 307.395118 -280.717498)
		(width 0.18288)
		(layer "In11.Cu")
		(net "M_D_CPU0_SA_DQS_DP<8>")
	)
	(segment
		(start 277.308564 -282.423362)
		(end 276.110446 -282.919424)
		(width 0.18288)
		(layer "In11.Cu")
		(net "M_D_CPU0_SA_DQS_DP<8>")
	)
	(segment
		(start 310.542432 -280.413968)
		(end 309.348124 -280.413968)
		(width 0.18288)
		(layer "In11.Cu")
		(net "M_D_CPU0_SA_DQS_DP<8>")
	)
	(segment
		(start 289.771328 -283.118306)
		(end 287.423098 -282.144978)
		(width 0.18288)
		(layer "In11.Cu")
		(net "M_D_CPU0_SA_DQS_DP<8>")
	)
	(segment
		(start 331.94879 -267.401294)
		(end 331.597762 -267.752322)
		(width 0.088646)
		(layer "In11.Cu")
		(net "M_D_CPU0_SA_DQS_DP<8>")
	)
	(segment
		(start 348.882462 -267.755878)
		(end 348.569788 -267.755878)
		(width 0.088646)
		(layer "In11.Cu")
		(net "M_D_CPU0_SA_DQS_DP<8>")
	)
	(segment
		(start 340.156546 -267.25753)
		(end 340.141814 -267.266166)
		(width 0.088646)
		(layer "In11.Cu")
		(net "M_D_CPU0_SA_DQS_DP<8>")
	)
	(segment
		(start 332.623414 -267.265912)
		(end 332.623668 -267.266674)
		(width 0.088646)
		(layer "In11.Cu")
		(net "M_D_CPU0_SA_DQS_DP<8>")
	)
	(segment
		(start 293.241984 -282.422346)
		(end 292.182804 -282.422346)
		(width 0.18288)
		(layer "In11.Cu")
		(net "M_D_CPU0_SA_DQS_DP<8>")
	)
	(segment
		(start 284.353 -282.144978)
		(end 284.098746 -281.890724)
		(width 0.18288)
		(layer "In11.Cu")
		(net "M_D_CPU0_SA_DQS_DP<8>")
	)
	(segment
		(start 278.13 -282.423362)
		(end 277.308564 -282.423362)
		(width 0.18288)
		(layer "In11.Cu")
		(net "M_D_CPU0_SA_DQS_DP<8>")
	)
	(segment
		(start 269.874238 -283.66212)
		(end 269.63497 -283.422852)
		(width 0.18288)
		(layer "In11.Cu")
		(net "M_D_CPU0_SA_DQS_DP<8>")
	)
	(segment
		(start 295.094406 -282.741624)
		(end 294.703754 -282.741624)
		(width 0.18288)
		(layer "In11.Cu")
		(net "M_D_CPU0_SA_DQS_DP<8>")
	)
	(segment
		(start 306.693316 -281.4193)
		(end 303.798732 -281.4193)
		(width 0.18288)
		(layer "In11.Cu")
		(net "M_D_CPU0_SA_DQS_DP<8>")
	)
	(segment
		(start 298.808902 -281.890724)
		(end 298.546774 -282.152852)
		(width 0.18288)
		(layer "In11.Cu")
		(net "M_D_CPU0_SA_DQS_DP<8>")
	)
	(segment
		(start 287.423098 -282.144978)
		(end 284.353 -282.144978)
		(width 0.18288)
		(layer "In11.Cu")
		(net "M_D_CPU0_SA_DQS_DP<8>")
	)
	(segment
		(start 307.395118 -280.717498)
		(end 306.693316 -281.4193)
		(width 0.18288)
		(layer "In11.Cu")
		(net "M_D_CPU0_SA_DQS_DP<8>")
	)
	(segment
		(start 274.317206 -282.919424)
		(end 272.523966 -283.66212)
		(width 0.18288)
		(layer "In11.Cu")
		(net "M_D_CPU0_SA_DQS_DP<8>")
	)
	(segment
		(start 295.351962 -282.99918)
		(end 295.094406 -282.741624)
		(width 0.18288)
		(layer "In11.Cu")
		(net "M_D_CPU0_SA_DQS_DP<8>")
	)
	(segment
		(start 299.47108 -282.173934)
		(end 299.18787 -281.890724)
		(width 0.18288)
		(layer "In11.Cu")
		(net "M_D_CPU0_SA_DQS_DP<8>")
	)
	(segment
		(start 278.730456 -283.023818)
		(end 278.13 -282.423362)
		(width 0.18288)
		(layer "In11.Cu")
		(net "M_D_CPU0_SA_DQS_DP<8>")
	)
	(segment
		(start 331.597762 -267.752322)
		(end 331.597762 -268.308328)
		(width 0.088646)
		(layer "In11.Cu")
		(net "M_D_CPU0_SA_DQS_DP<8>")
	)
	(segment
		(start 338.827364 -267.266166)
		(end 338.812632 -267.25753)
		(width 0.088646)
		(layer "In11.Cu")
		(net "M_D_CPU0_SA_DQS_DP<8>")
	)
	(segment
		(start 325.556372 -268.770354)
		(end 314.645294 -279.681432)
		(width 0.18288)
		(layer "In11.Cu")
		(net "M_D_CPU0_SA_DQS_DP<8>")
	)
	(segment
		(start 280.271728 -283.01061)
		(end 280.001726 -282.740608)
		(width 0.18288)
		(layer "In11.Cu")
		(net "M_D_CPU0_SA_DQS_DP<8>")
	)
	(segment
		(start 299.18787 -281.890724)
		(end 298.808902 -281.890724)
		(width 0.18288)
		(layer "In11.Cu")
		(net "M_D_CPU0_SA_DQS_DP<8>")
	)
	(segment
		(start 298.546774 -282.152852)
		(end 297.659298 -282.152852)
		(width 0.18288)
		(layer "In11.Cu")
		(net "M_D_CPU0_SA_DQS_DP<8>")
	)
	(segment
		(start 314.645294 -279.681432)
		(end 311.274968 -279.681432)
		(width 0.18288)
		(layer "In11.Cu")
		(net "M_D_CPU0_SA_DQS_DP<8>")
	)
	(segment
		(start 345.405964 -267.266166)
		(end 345.39555 -267.26007)
		(width 0.088646)
		(layer "In11.Cu")
		(net "M_D_CPU0_SA_DQS_DP<8>")
	)
	(segment
		(start 276.110446 -282.919424)
		(end 274.317206 -282.919424)
		(width 0.18288)
		(layer "In11.Cu")
		(net "M_D_CPU0_SA_DQS_DP<8>")
	)
	(segment
		(start 343.915746 -267.25753)
		(end 343.901014 -267.266166)
		(width 0.088646)
		(layer "In11.Cu")
		(net "M_D_CPU0_SA_DQS_DP<8>")
	)
	(segment
		(start 341.096346 -267.25753)
		(end 341.081614 -267.266166)
		(width 0.088646)
		(layer "In11.Cu")
		(net "M_D_CPU0_SA_DQS_DP<8>")
	)
	(segment
		(start 347.674946 -267.25753)
		(end 347.660214 -267.266166)
		(width 0.088646)
		(layer "In11.Cu")
		(net "M_D_CPU0_SA_DQS_DP<8>")
	)
	(segment
		(start 348.569788 -267.755878)
		(end 348.50451 -267.6906)
		(width 0.088646)
		(layer "In11.Cu")
		(net "M_D_CPU0_SA_DQS_DP<8>")
	)
	(segment
		(start 330.98613 -268.830044)
		(end 330.92644 -268.770354)
		(width 0.088646)
		(layer "In11.Cu")
		(net "M_D_CPU0_SA_DQS_DP<8>")
	)
	(segment
		(start 291.138356 -283.118306)
		(end 289.771328 -283.118306)
		(width 0.18288)
		(layer "In11.Cu")
		(net "M_D_CPU0_SA_DQS_DP<8>")
	)
	(segment
		(start 280.001726 -282.740608)
		(end 279.633426 -282.740608)
		(width 0.18288)
		(layer "In11.Cu")
		(net "M_D_CPU0_SA_DQS_DP<8>")
	)
	(segment
		(start 331.302868 -268.603222)
		(end 331.302868 -268.726158)
		(width 0.088646)
		(layer "In11.Cu")
		(net "M_D_CPU0_SA_DQS_DP<8>")
	)
	(segment
		(start 283.726382 -281.890724)
		(end 283.454856 -282.16225)
		(width 0.18288)
		(layer "In11.Cu")
		(net "M_D_CPU0_SA_DQS_DP<8>")
	)
	(segment
		(start 294.703754 -282.741624)
		(end 294.441626 -283.003752)
		(width 0.18288)
		(layer "In11.Cu")
		(net "M_D_CPU0_SA_DQS_DP<8>")
	)
	(segment
		(start 342.975946 -267.25753)
		(end 342.961214 -267.266166)
		(width 0.088646)
		(layer "In11.Cu")
		(net "M_D_CPU0_SA_DQS_DP<8>")
	)
	(segment
		(start 331.597762 -268.308328)
		(end 331.302868 -268.603222)
		(width 0.088646)
		(layer "In11.Cu")
		(net "M_D_CPU0_SA_DQS_DP<8>")
	)
	(segment
		(start 330.92644 -268.770354)
		(end 325.556372 -268.770354)
		(width 0.18288)
		(layer "In11.Cu")
		(net "M_D_CPU0_SA_DQS_DP<8>")
	)
	(segment
		(start 342.036146 -267.25753)
		(end 342.021414 -267.266166)
		(width 0.088646)
		(layer "In11.Cu")
		(net "M_D_CPU0_SA_DQS_DP<8>")
	)
	(segment
		(start 296.81297 -282.99918)
		(end 295.351962 -282.99918)
		(width 0.18288)
		(layer "In11.Cu")
		(net "M_D_CPU0_SA_DQS_DP<8>")
	)
	(segment
		(start 279.350216 -283.023818)
		(end 278.730456 -283.023818)
		(width 0.18288)
		(layer "In11.Cu")
		(net "M_D_CPU0_SA_DQS_DP<8>")
	)
	(segment
		(start 281.610308 -283.01061)
		(end 280.271728 -283.01061)
		(width 0.18288)
		(layer "In11.Cu")
		(net "M_D_CPU0_SA_DQS_DP<8>")
	)
	(segment
		(start 309.348124 -280.413968)
		(end 309.044594 -280.717498)
		(width 0.18288)
		(layer "In11.Cu")
		(net "M_D_CPU0_SA_DQS_DP<8>")
	)
	(segment
		(start 294.441626 -283.003752)
		(end 293.82339 -283.003752)
		(width 0.18288)
		(layer "In11.Cu")
		(net "M_D_CPU0_SA_DQS_DP<8>")
	)
	(segment
		(start 303.044098 -282.173934)
		(end 299.47108 -282.173934)
		(width 0.18288)
		(layer "In11.Cu")
		(net "M_D_CPU0_SA_DQS_DP<8>")
	)
	(segment
		(start 311.274968 -279.681432)
		(end 310.542432 -280.413968)
		(width 0.18288)
		(layer "In11.Cu")
		(net "M_D_CPU0_SA_DQS_DP<8>")
	)
	(segment
		(start 291.73297 -282.871926)
		(end 291.138356 -283.118306)
		(width 0.18288)
		(layer "In11.Cu")
		(net "M_D_CPU0_SA_DQS_DP<8>")
	)
	(segment
		(start 283.094176 -282.16225)
		(end 282.69565 -282.560776)
		(width 0.18288)
		(layer "In11.Cu")
		(net "M_D_CPU0_SA_DQS_DP<8>")
	)
	(segment
		(start 293.82339 -283.003752)
		(end 293.241984 -282.422346)
		(width 0.18288)
		(layer "In11.Cu")
		(net "M_D_CPU0_SA_DQS_DP<8>")
	)
	(segment
		(start 332.152244 -267.316966)
		(end 331.94879 -267.401294)
		(width 0.088646)
		(layer "In11.Cu")
		(net "M_D_CPU0_SA_DQS_DP<8>")
	)
	(segment
		(start 297.659298 -282.152852)
		(end 296.81297 -282.99918)
		(width 0.18288)
		(layer "In11.Cu")
		(net "M_D_CPU0_SA_DQS_DP<8>")
	)
	(segment
		(start 331.302868 -268.726158)
		(end 331.198982 -268.830044)
		(width 0.088646)
		(layer "In11.Cu")
		(net "M_D_CPU0_SA_DQS_DP<8>")
	)
	(segment
		(start 279.633426 -282.740608)
		(end 279.350216 -283.023818)
		(width 0.18288)
		(layer "In11.Cu")
		(net "M_D_CPU0_SA_DQS_DP<8>")
	)
	(segment
		(start 345.790774 -267.26007)
		(end 345.78036 -267.266166)
		(width 0.088646)
		(layer "In11.Cu")
		(net "M_D_CPU0_SA_DQS_DP<8>")
	)
	(segment
		(start 336.382868 -267.266674)
		(end 336.38236 -267.266166)
		(width 0.088646)
		(layer "In11.Cu")
		(net "M_D_CPU0_SA_DQS_DP<8>")
	)
	(segment
		(start 272.523966 -283.66212)
		(end 269.874238 -283.66212)
		(width 0.18288)
		(layer "In11.Cu")
		(net "M_D_CPU0_SA_DQS_DP<8>")
	)
	(segment
		(start 336.947764 -267.266166)
		(end 336.947256 -267.266674)
		(width 0.088646)
		(layer "In11.Cu")
		(net "M_D_CPU0_SA_DQS_DP<8>")
	)
	(segment
		(start 269.085568 -283.422852)
		(end 268.829282 -283.166566)
		(width 0.18288)
		(layer "In11.Cu")
		(net "M_D_CPU0_SA_DQS_DP<8>")
	)
	(segment
		(start 283.454856 -282.16225)
		(end 283.094176 -282.16225)
		(width 0.18288)
		(layer "In11.Cu")
		(net "M_D_CPU0_SA_DQS_DP<8>")
	)
	(segment
		(start 331.198982 -268.830044)
		(end 330.98613 -268.830044)
		(width 0.088646)
		(layer "In11.Cu")
		(net "M_D_CPU0_SA_DQS_DP<8>")
	)
	(arc
		(start 333.56296 -267.266166)
		(mid 333.375762 -267.316309)
		(end 333.188564 -267.266166)
		(width 0.088646)
		(layer "In11.Cu")
		(net "M_D_CPU0_SA_DQS_DP<8>")
	)
	(arc
		(start 346.720414 -267.266166)
		(mid 346.533216 -267.316309)
		(end 346.346018 -267.266166)
		(width 0.088646)
		(layer "In11.Cu")
		(net "M_D_CPU0_SA_DQS_DP<8>")
	)
	(arc
		(start 348.501716 -267.669264)
		(mid 348.194858 -267.249478)
		(end 347.674946 -267.25753)
		(width 0.088646)
		(layer "In11.Cu")
		(net "M_D_CPU0_SA_DQS_DP<8>")
	)
	(arc
		(start 334.50276 -267.266166)
		(mid 334.315562 -267.316309)
		(end 334.128364 -267.266166)
		(width 0.088646)
		(layer "In11.Cu")
		(net "M_D_CPU0_SA_DQS_DP<8>")
	)
	(arc
		(start 345.39555 -267.26007)
		(mid 345.117372 -267.190378)
		(end 344.840814 -267.266166)
		(width 0.088646)
		(layer "In11.Cu")
		(net "M_D_CPU0_SA_DQS_DP<8>")
	)
	(arc
		(start 335.068164 -267.266166)
		(mid 334.785462 -267.190424)
		(end 334.50276 -267.266166)
		(width 0.088646)
		(layer "In11.Cu")
		(net "M_D_CPU0_SA_DQS_DP<8>")
	)
	(arc
		(start 333.188564 -267.266166)
		(mid 332.906035 -267.190424)
		(end 332.623414 -267.265912)
		(width 0.088646)
		(layer "In11.Cu")
		(net "M_D_CPU0_SA_DQS_DP<8>")
	)
	(arc
		(start 339.20176 -267.266166)
		(mid 339.014562 -267.316309)
		(end 338.827364 -267.266166)
		(width 0.088646)
		(layer "In11.Cu")
		(net "M_D_CPU0_SA_DQS_DP<8>")
	)
	(arc
		(start 337.887564 -267.266166)
		(mid 337.604862 -267.190424)
		(end 337.32216 -267.266166)
		(width 0.088646)
		(layer "In11.Cu")
		(net "M_D_CPU0_SA_DQS_DP<8>")
	)
	(arc
		(start 348.50451 -267.6906)
		(mid 348.503215 -267.679919)
		(end 348.501716 -267.669264)
		(width 0.088646)
		(layer "In11.Cu")
		(net "M_D_CPU0_SA_DQS_DP<8>")
	)
	(arc
		(start 347.285818 -267.266166)
		(mid 347.011589 -267.190241)
		(end 346.735146 -267.25753)
		(width 0.088646)
		(layer "In11.Cu")
		(net "M_D_CPU0_SA_DQS_DP<8>")
	)
	(arc
		(start 334.128364 -267.266166)
		(mid 333.845662 -267.190424)
		(end 333.56296 -267.266166)
		(width 0.088646)
		(layer "In11.Cu")
		(net "M_D_CPU0_SA_DQS_DP<8>")
	)
	(arc
		(start 340.141814 -267.266166)
		(mid 339.954616 -267.316309)
		(end 339.767418 -267.266166)
		(width 0.088646)
		(layer "In11.Cu")
		(net "M_D_CPU0_SA_DQS_DP<8>")
	)
	(arc
		(start 337.32216 -267.266166)
		(mid 337.134962 -267.316309)
		(end 336.947764 -267.266166)
		(width 0.088646)
		(layer "In11.Cu")
		(net "M_D_CPU0_SA_DQS_DP<8>")
	)
	(arc
		(start 342.021414 -267.266166)
		(mid 341.834216 -267.316309)
		(end 341.647018 -267.266166)
		(width 0.088646)
		(layer "In11.Cu")
		(net "M_D_CPU0_SA_DQS_DP<8>")
	)
	(arc
		(start 336.38236 -267.266166)
		(mid 336.195162 -267.316309)
		(end 336.007964 -267.266166)
		(width 0.088646)
		(layer "In11.Cu")
		(net "M_D_CPU0_SA_DQS_DP<8>")
	)
	(arc
		(start 341.081614 -267.266166)
		(mid 340.894416 -267.316309)
		(end 340.707218 -267.266166)
		(width 0.088646)
		(layer "In11.Cu")
		(net "M_D_CPU0_SA_DQS_DP<8>")
	)
	(arc
		(start 338.812632 -267.25753)
		(mid 338.536191 -267.190364)
		(end 338.26196 -267.266166)
		(width 0.088646)
		(layer "In11.Cu")
		(net "M_D_CPU0_SA_DQS_DP<8>")
	)
	(arc
		(start 347.660214 -267.266166)
		(mid 347.473016 -267.316309)
		(end 347.285818 -267.266166)
		(width 0.088646)
		(layer "In11.Cu")
		(net "M_D_CPU0_SA_DQS_DP<8>")
	)
	(arc
		(start 343.901014 -267.266166)
		(mid 343.713816 -267.316309)
		(end 343.526618 -267.266166)
		(width 0.088646)
		(layer "In11.Cu")
		(net "M_D_CPU0_SA_DQS_DP<8>")
	)
	(arc
		(start 346.346018 -267.266166)
		(mid 346.069205 -267.19033)
		(end 345.790774 -267.26007)
		(width 0.088646)
		(layer "In11.Cu")
		(net "M_D_CPU0_SA_DQS_DP<8>")
	)
	(arc
		(start 335.44256 -267.266166)
		(mid 335.255362 -267.316309)
		(end 335.068164 -267.266166)
		(width 0.088646)
		(layer "In11.Cu")
		(net "M_D_CPU0_SA_DQS_DP<8>")
	)
	(arc
		(start 342.586818 -267.266166)
		(mid 342.312589 -267.190241)
		(end 342.036146 -267.25753)
		(width 0.088646)
		(layer "In11.Cu")
		(net "M_D_CPU0_SA_DQS_DP<8>")
	)
	(arc
		(start 332.623668 -267.266674)
		(mid 332.533253 -267.30417)
		(end 332.436216 -267.316966)
		(width 0.088646)
		(layer "In11.Cu")
		(net "M_D_CPU0_SA_DQS_DP<8>")
	)
	(arc
		(start 341.647018 -267.266166)
		(mid 341.372789 -267.190241)
		(end 341.096346 -267.25753)
		(width 0.088646)
		(layer "In11.Cu")
		(net "M_D_CPU0_SA_DQS_DP<8>")
	)
	(arc
		(start 336.947256 -267.266674)
		(mid 336.665062 -267.191118)
		(end 336.382868 -267.266674)
		(width 0.088646)
		(layer "In11.Cu")
		(net "M_D_CPU0_SA_DQS_DP<8>")
	)
	(arc
		(start 344.840814 -267.266166)
		(mid 344.653616 -267.316309)
		(end 344.466418 -267.266166)
		(width 0.088646)
		(layer "In11.Cu")
		(net "M_D_CPU0_SA_DQS_DP<8>")
	)
	(arc
		(start 343.526618 -267.266166)
		(mid 343.252389 -267.190241)
		(end 342.975946 -267.25753)
		(width 0.088646)
		(layer "In11.Cu")
		(net "M_D_CPU0_SA_DQS_DP<8>")
	)
	(arc
		(start 342.961214 -267.266166)
		(mid 342.774016 -267.316309)
		(end 342.586818 -267.266166)
		(width 0.088646)
		(layer "In11.Cu")
		(net "M_D_CPU0_SA_DQS_DP<8>")
	)
	(arc
		(start 339.767418 -267.266166)
		(mid 339.490605 -267.19033)
		(end 339.212174 -267.26007)
		(width 0.088646)
		(layer "In11.Cu")
		(net "M_D_CPU0_SA_DQS_DP<8>")
	)
	(arc
		(start 340.707218 -267.266166)
		(mid 340.432989 -267.190241)
		(end 340.156546 -267.25753)
		(width 0.088646)
		(layer "In11.Cu")
		(net "M_D_CPU0_SA_DQS_DP<8>")
	)
	(arc
		(start 338.26196 -267.266166)
		(mid 338.074762 -267.316309)
		(end 337.887564 -267.266166)
		(width 0.088646)
		(layer "In11.Cu")
		(net "M_D_CPU0_SA_DQS_DP<8>")
	)
	(arc
		(start 345.78036 -267.266166)
		(mid 345.593162 -267.316309)
		(end 345.405964 -267.266166)
		(width 0.088646)
		(layer "In11.Cu")
		(net "M_D_CPU0_SA_DQS_DP<8>")
	)
	(arc
		(start 336.007964 -267.266166)
		(mid 335.725262 -267.190424)
		(end 335.44256 -267.266166)
		(width 0.088646)
		(layer "In11.Cu")
		(net "M_D_CPU0_SA_DQS_DP<8>")
	)
	(arc
		(start 344.466418 -267.266166)
		(mid 344.192189 -267.190241)
		(end 343.915746 -267.25753)
		(width 0.088646)
		(layer "In11.Cu")
		(net "M_D_CPU0_SA_DQS_DP<8>")
	)
	(segment
		(start 260.655308 -292.516814)
		(end 260.180582 -292.516814)
		(width 0.20066)
		(layer "F.Cu")
		(net "M_D_CPU0_SA_DQS_DP<7>")
	)
	(segment
		(start 266.368784 -292.777926)
		(end 265.732768 -292.352984)
		(width 0.20066)
		(layer "F.Cu")
		(net "M_D_CPU0_SA_DQS_DP<7>")
	)
	(segment
		(start 264.966704 -292.091872)
		(end 264.825226 -292.091872)
		(width 0.20066)
		(layer "F.Cu")
		(net "M_D_CPU0_SA_DQS_DP<7>")
	)
	(segment
		(start 261.673086 -292.355524)
		(end 261.250684 -292.777926)
		(width 0.20066)
		(layer "F.Cu")
		(net "M_D_CPU0_SA_DQS_DP<7>")
	)
	(segment
		(start 260.91642 -292.777926)
		(end 260.655308 -292.516814)
		(width 0.20066)
		(layer "F.Cu")
		(net "M_D_CPU0_SA_DQS_DP<7>")
	)
	(segment
		(start 267.234416 -292.516814)
		(end 266.973304 -292.777926)
		(width 0.20066)
		(layer "F.Cu")
		(net "M_D_CPU0_SA_DQS_DP<7>")
	)
	(segment
		(start 261.250684 -292.777926)
		(end 260.91642 -292.777926)
		(width 0.20066)
		(layer "F.Cu")
		(net "M_D_CPU0_SA_DQS_DP<7>")
	)
	(segment
		(start 264.825226 -292.091872)
		(end 262.746744 -292.091872)
		(width 0.1016)
		(layer "F.Cu")
		(net "M_D_CPU0_SA_DQS_DP<7>")
	)
	(segment
		(start 266.973304 -292.777926)
		(end 266.368784 -292.777926)
		(width 0.20066)
		(layer "F.Cu")
		(net "M_D_CPU0_SA_DQS_DP<7>")
	)
	(segment
		(start 262.50011 -292.08603)
		(end 262.302752 -292.08603)
		(width 0.20066)
		(layer "F.Cu")
		(net "M_D_CPU0_SA_DQS_DP<7>")
	)
	(segment
		(start 267.724382 -292.516814)
		(end 267.234416 -292.516814)
		(width 0.20066)
		(layer "F.Cu")
		(net "M_D_CPU0_SA_DQS_DP<7>")
	)
	(segment
		(start 265.227816 -292.352984)
		(end 264.966704 -292.091872)
		(width 0.20066)
		(layer "F.Cu")
		(net "M_D_CPU0_SA_DQS_DP<7>")
	)
	(segment
		(start 262.302752 -292.08603)
		(end 262.033258 -292.355524)
		(width 0.20066)
		(layer "F.Cu")
		(net "M_D_CPU0_SA_DQS_DP<7>")
	)
	(segment
		(start 262.033258 -292.355524)
		(end 261.673086 -292.355524)
		(width 0.20066)
		(layer "F.Cu")
		(net "M_D_CPU0_SA_DQS_DP<7>")
	)
	(segment
		(start 262.505952 -292.091872)
		(end 262.50011 -292.08603)
		(width 0.101854)
		(layer "F.Cu")
		(net "M_D_CPU0_SA_DQS_DP<7>")
	)
	(segment
		(start 265.732768 -292.352984)
		(end 265.227816 -292.352984)
		(width 0.20066)
		(layer "F.Cu")
		(net "M_D_CPU0_SA_DQS_DP<7>")
	)
	(segment
		(start 268.829282 -292.516814)
		(end 267.724382 -292.516814)
		(width 0.20066)
		(layer "F.Cu")
		(net "M_D_CPU0_SA_DQS_DP<7>")
	)
	(segment
		(start 262.746744 -292.091872)
		(end 262.505952 -292.091872)
		(width 0.101854)
		(layer "F.Cu")
		(net "M_D_CPU0_SA_DQS_DP<7>")
	)
	(arc
		(start 348.882716 -272.103342)
		(mid 348.882652 -272.371312)
		(end 348.882462 -272.639282)
		(width 0.20066)
		(layer "F.Cu")
		(net "M_D_CPU0_SA_DQS_DP<7>")
	)
	(segment
		(start 345.790774 -272.143474)
		(end 345.78036 -272.14957)
		(width 0.088646)
		(layer "In11.Cu")
		(net "M_D_CPU0_SA_DQS_DP<7>")
	)
	(segment
		(start 276.746462 -295.081706)
		(end 276.37994 -295.081706)
		(width 0.18288)
		(layer "In11.Cu")
		(net "M_D_CPU0_SA_DQS_DP<7>")
	)
	(segment
		(start 290.791392 -294.546782)
		(end 289.696398 -293.451788)
		(width 0.18288)
		(layer "In11.Cu")
		(net "M_D_CPU0_SA_DQS_DP<7>")
	)
	(segment
		(start 347.674946 -272.140934)
		(end 347.660214 -272.14957)
		(width 0.088646)
		(layer "In11.Cu")
		(net "M_D_CPU0_SA_DQS_DP<7>")
	)
	(segment
		(start 331.028294 -274.785074)
		(end 328.296524 -274.785074)
		(width 0.18288)
		(layer "In11.Cu")
		(net "M_D_CPU0_SA_DQS_DP<7>")
	)
	(segment
		(start 270.097504 -293.008812)
		(end 269.548864 -292.781736)
		(width 0.18288)
		(layer "In11.Cu")
		(net "M_D_CPU0_SA_DQS_DP<7>")
	)
	(segment
		(start 278.680418 -294.908732)
		(end 278.053038 -295.536112)
		(width 0.18288)
		(layer "In11.Cu")
		(net "M_D_CPU0_SA_DQS_DP<7>")
	)
	(segment
		(start 337.332828 -272.143474)
		(end 337.322414 -272.14957)
		(width 0.088646)
		(layer "In11.Cu")
		(net "M_D_CPU0_SA_DQS_DP<7>")
	)
	(segment
		(start 298.813982 -293.790878)
		(end 298.483528 -294.121332)
		(width 0.18288)
		(layer "In11.Cu")
		(net "M_D_CPU0_SA_DQS_DP<7>")
	)
	(segment
		(start 332.678786 -272.073878)
		(end 332.224888 -272.527776)
		(width 0.088646)
		(layer "In11.Cu")
		(net "M_D_CPU0_SA_DQS_DP<7>")
	)
	(segment
		(start 269.094204 -292.781736)
		(end 268.829282 -292.516814)
		(width 0.18288)
		(layer "In11.Cu")
		(net "M_D_CPU0_SA_DQS_DP<7>")
	)
	(segment
		(start 284.099762 -293.790878)
		(end 283.720794 -293.790878)
		(width 0.18288)
		(layer "In11.Cu")
		(net "M_D_CPU0_SA_DQS_DP<7>")
	)
	(segment
		(start 343.915746 -272.140934)
		(end 343.901014 -272.14957)
		(width 0.088646)
		(layer "In11.Cu")
		(net "M_D_CPU0_SA_DQS_DP<7>")
	)
	(segment
		(start 281.95143 -294.910002)
		(end 280.356564 -294.910002)
		(width 0.18288)
		(layer "In11.Cu")
		(net "M_D_CPU0_SA_DQS_DP<7>")
	)
	(segment
		(start 301.433992 -292.958266)
		(end 300.317154 -294.07485)
		(width 0.18288)
		(layer "In11.Cu")
		(net "M_D_CPU0_SA_DQS_DP<7>")
	)
	(segment
		(start 278.053038 -295.536112)
		(end 277.200868 -295.536112)
		(width 0.18288)
		(layer "In11.Cu")
		(net "M_D_CPU0_SA_DQS_DP<7>")
	)
	(segment
		(start 298.07535 -294.121332)
		(end 296.725086 -294.913304)
		(width 0.18288)
		(layer "In11.Cu")
		(net "M_D_CPU0_SA_DQS_DP<7>")
	)
	(segment
		(start 340.156546 -272.140934)
		(end 340.141814 -272.14957)
		(width 0.088646)
		(layer "In11.Cu")
		(net "M_D_CPU0_SA_DQS_DP<7>")
	)
	(segment
		(start 269.548864 -292.781736)
		(end 269.094204 -292.781736)
		(width 0.18288)
		(layer "In11.Cu")
		(net "M_D_CPU0_SA_DQS_DP<7>")
	)
	(segment
		(start 306.526184 -290.908486)
		(end 305.849782 -290.908486)
		(width 0.18288)
		(layer "In11.Cu")
		(net "M_D_CPU0_SA_DQS_DP<7>")
	)
	(segment
		(start 345.405964 -272.14957)
		(end 345.39555 -272.143474)
		(width 0.088646)
		(layer "In11.Cu")
		(net "M_D_CPU0_SA_DQS_DP<7>")
	)
	(segment
		(start 331.343 -274.723098)
		(end 331.221334 -274.844764)
		(width 0.088646)
		(layer "In11.Cu")
		(net "M_D_CPU0_SA_DQS_DP<7>")
	)
	(segment
		(start 293.823644 -294.912288)
		(end 293.218362 -294.307006)
		(width 0.18288)
		(layer "In11.Cu")
		(net "M_D_CPU0_SA_DQS_DP<7>")
	)
	(segment
		(start 285.943294 -293.890192)
		(end 285.914846 -293.91864)
		(width 0.18288)
		(layer "In11.Cu")
		(net "M_D_CPU0_SA_DQS_DP<7>")
	)
	(segment
		(start 339.212174 -272.143474)
		(end 339.20176 -272.14957)
		(width 0.088646)
		(layer "In11.Cu")
		(net "M_D_CPU0_SA_DQS_DP<7>")
	)
	(segment
		(start 348.569788 -272.639282)
		(end 348.50451 -272.574004)
		(width 0.088646)
		(layer "In11.Cu")
		(net "M_D_CPU0_SA_DQS_DP<7>")
	)
	(segment
		(start 280.356564 -294.910002)
		(end 280.087578 -294.641016)
		(width 0.18288)
		(layer "In11.Cu")
		(net "M_D_CPU0_SA_DQS_DP<7>")
	)
	(segment
		(start 332.224888 -273.502628)
		(end 331.343 -274.384516)
		(width 0.088646)
		(layer "In11.Cu")
		(net "M_D_CPU0_SA_DQS_DP<7>")
	)
	(segment
		(start 332.224888 -272.527776)
		(end 332.224888 -272.665444)
		(width 0.088646)
		(layer "In11.Cu")
		(net "M_D_CPU0_SA_DQS_DP<7>")
	)
	(segment
		(start 342.036146 -272.140934)
		(end 342.021414 -272.14957)
		(width 0.088646)
		(layer "In11.Cu")
		(net "M_D_CPU0_SA_DQS_DP<7>")
	)
	(segment
		(start 338.827364 -272.14957)
		(end 338.812632 -272.140934)
		(width 0.088646)
		(layer "In11.Cu")
		(net "M_D_CPU0_SA_DQS_DP<7>")
	)
	(segment
		(start 277.200868 -295.536112)
		(end 276.746462 -295.081706)
		(width 0.18288)
		(layer "In11.Cu")
		(net "M_D_CPU0_SA_DQS_DP<7>")
	)
	(segment
		(start 332.224888 -272.665444)
		(end 332.224634 -272.665698)
		(width 0.088646)
		(layer "In11.Cu")
		(net "M_D_CPU0_SA_DQS_DP<7>")
	)
	(segment
		(start 285.914846 -293.91864)
		(end 285.570168 -294.061388)
		(width 0.18288)
		(layer "In11.Cu")
		(net "M_D_CPU0_SA_DQS_DP<7>")
	)
	(segment
		(start 284.370272 -294.061388)
		(end 284.099762 -293.790878)
		(width 0.18288)
		(layer "In11.Cu")
		(net "M_D_CPU0_SA_DQS_DP<7>")
	)
	(segment
		(start 335.068164 -272.14957)
		(end 335.053432 -272.140934)
		(width 0.088646)
		(layer "In11.Cu")
		(net "M_D_CPU0_SA_DQS_DP<7>")
	)
	(segment
		(start 341.096346 -272.140934)
		(end 341.081614 -272.14957)
		(width 0.088646)
		(layer "In11.Cu")
		(net "M_D_CPU0_SA_DQS_DP<7>")
	)
	(segment
		(start 288.12744 -293.890192)
		(end 285.943294 -293.890192)
		(width 0.18288)
		(layer "In11.Cu")
		(net "M_D_CPU0_SA_DQS_DP<7>")
	)
	(segment
		(start 299.478446 -294.07485)
		(end 299.194474 -293.790878)
		(width 0.18288)
		(layer "In11.Cu")
		(net "M_D_CPU0_SA_DQS_DP<7>")
	)
	(segment
		(start 295.13403 -294.641016)
		(end 294.713914 -294.641016)
		(width 0.18288)
		(layer "In11.Cu")
		(net "M_D_CPU0_SA_DQS_DP<7>")
	)
	(segment
		(start 296.725086 -294.913304)
		(end 295.406318 -294.913304)
		(width 0.18288)
		(layer "In11.Cu")
		(net "M_D_CPU0_SA_DQS_DP<7>")
	)
	(segment
		(start 302.741076 -292.958266)
		(end 301.433992 -292.958266)
		(width 0.18288)
		(layer "In11.Cu")
		(net "M_D_CPU0_SA_DQS_DP<7>")
	)
	(segment
		(start 285.570168 -294.061388)
		(end 284.370272 -294.061388)
		(width 0.18288)
		(layer "In11.Cu")
		(net "M_D_CPU0_SA_DQS_DP<7>")
	)
	(segment
		(start 273.351752 -293.008812)
		(end 270.097504 -293.008812)
		(width 0.18288)
		(layer "In11.Cu")
		(net "M_D_CPU0_SA_DQS_DP<7>")
	)
	(segment
		(start 280.087578 -294.641016)
		(end 279.624282 -294.641016)
		(width 0.18288)
		(layer "In11.Cu")
		(net "M_D_CPU0_SA_DQS_DP<7>")
	)
	(segment
		(start 289.696398 -293.451788)
		(end 288.565844 -293.451788)
		(width 0.18288)
		(layer "In11.Cu")
		(net "M_D_CPU0_SA_DQS_DP<7>")
	)
	(segment
		(start 331.343 -274.384516)
		(end 331.343 -274.723098)
		(width 0.088646)
		(layer "In11.Cu")
		(net "M_D_CPU0_SA_DQS_DP<7>")
	)
	(segment
		(start 288.565844 -293.451788)
		(end 288.12744 -293.890192)
		(width 0.18288)
		(layer "In11.Cu")
		(net "M_D_CPU0_SA_DQS_DP<7>")
	)
	(segment
		(start 304.548794 -292.209474)
		(end 302.741076 -292.958266)
		(width 0.18288)
		(layer "In11.Cu")
		(net "M_D_CPU0_SA_DQS_DP<7>")
	)
	(segment
		(start 282.806648 -294.054784)
		(end 281.95143 -294.910002)
		(width 0.18288)
		(layer "In11.Cu")
		(net "M_D_CPU0_SA_DQS_DP<7>")
	)
	(segment
		(start 276.37994 -295.081706)
		(end 274.982432 -293.683944)
		(width 0.18288)
		(layer "In11.Cu")
		(net "M_D_CPU0_SA_DQS_DP<7>")
	)
	(segment
		(start 328.296524 -274.785074)
		(end 314.097162 -288.984436)
		(width 0.18288)
		(layer "In11.Cu")
		(net "M_D_CPU0_SA_DQS_DP<7>")
	)
	(segment
		(start 310.539892 -290.07308)
		(end 307.36159 -290.07308)
		(width 0.18288)
		(layer "In11.Cu")
		(net "M_D_CPU0_SA_DQS_DP<7>")
	)
	(segment
		(start 283.720794 -293.790878)
		(end 283.456888 -294.054784)
		(width 0.18288)
		(layer "In11.Cu")
		(net "M_D_CPU0_SA_DQS_DP<7>")
	)
	(segment
		(start 300.317154 -294.07485)
		(end 299.478446 -294.07485)
		(width 0.18288)
		(layer "In11.Cu")
		(net "M_D_CPU0_SA_DQS_DP<7>")
	)
	(segment
		(start 295.406318 -294.913304)
		(end 295.13403 -294.641016)
		(width 0.18288)
		(layer "In11.Cu")
		(net "M_D_CPU0_SA_DQS_DP<7>")
	)
	(segment
		(start 294.442642 -294.912288)
		(end 293.823644 -294.912288)
		(width 0.18288)
		(layer "In11.Cu")
		(net "M_D_CPU0_SA_DQS_DP<7>")
	)
	(segment
		(start 332.224634 -272.665698)
		(end 332.224888 -272.665952)
		(width 0.088646)
		(layer "In11.Cu")
		(net "M_D_CPU0_SA_DQS_DP<7>")
	)
	(segment
		(start 348.882462 -272.639282)
		(end 348.569788 -272.639282)
		(width 0.088646)
		(layer "In11.Cu")
		(net "M_D_CPU0_SA_DQS_DP<7>")
	)
	(segment
		(start 293.218362 -294.307006)
		(end 292.231826 -294.307006)
		(width 0.18288)
		(layer "In11.Cu")
		(net "M_D_CPU0_SA_DQS_DP<7>")
	)
	(segment
		(start 332.906116 -272.073878)
		(end 332.678786 -272.073878)
		(width 0.088646)
		(layer "In11.Cu")
		(net "M_D_CPU0_SA_DQS_DP<7>")
	)
	(segment
		(start 279.624282 -294.641016)
		(end 279.356566 -294.908732)
		(width 0.18288)
		(layer "In11.Cu")
		(net "M_D_CPU0_SA_DQS_DP<7>")
	)
	(segment
		(start 283.456888 -294.054784)
		(end 282.806648 -294.054784)
		(width 0.18288)
		(layer "In11.Cu")
		(net "M_D_CPU0_SA_DQS_DP<7>")
	)
	(segment
		(start 291.336222 -294.74287)
		(end 290.791392 -294.546782)
		(width 0.18288)
		(layer "In11.Cu")
		(net "M_D_CPU0_SA_DQS_DP<7>")
	)
	(segment
		(start 314.097162 -288.984436)
		(end 311.628536 -288.984436)
		(width 0.18288)
		(layer "In11.Cu")
		(net "M_D_CPU0_SA_DQS_DP<7>")
	)
	(segment
		(start 332.224888 -272.665952)
		(end 332.224888 -273.502628)
		(width 0.088646)
		(layer "In11.Cu")
		(net "M_D_CPU0_SA_DQS_DP<7>")
	)
	(segment
		(start 331.087984 -274.844764)
		(end 331.028294 -274.785074)
		(width 0.088646)
		(layer "In11.Cu")
		(net "M_D_CPU0_SA_DQS_DP<7>")
	)
	(segment
		(start 279.356566 -294.908732)
		(end 278.680418 -294.908732)
		(width 0.18288)
		(layer "In11.Cu")
		(net "M_D_CPU0_SA_DQS_DP<7>")
	)
	(segment
		(start 299.194474 -293.790878)
		(end 298.813982 -293.790878)
		(width 0.18288)
		(layer "In11.Cu")
		(net "M_D_CPU0_SA_DQS_DP<7>")
	)
	(segment
		(start 336.948018 -272.14957)
		(end 336.937604 -272.143474)
		(width 0.088646)
		(layer "In11.Cu")
		(net "M_D_CPU0_SA_DQS_DP<7>")
	)
	(segment
		(start 311.628536 -288.984436)
		(end 310.539892 -290.07308)
		(width 0.18288)
		(layer "In11.Cu")
		(net "M_D_CPU0_SA_DQS_DP<7>")
	)
	(segment
		(start 342.975946 -272.140934)
		(end 342.961214 -272.14957)
		(width 0.088646)
		(layer "In11.Cu")
		(net "M_D_CPU0_SA_DQS_DP<7>")
	)
	(segment
		(start 274.982432 -293.683944)
		(end 273.351752 -293.008812)
		(width 0.18288)
		(layer "In11.Cu")
		(net "M_D_CPU0_SA_DQS_DP<7>")
	)
	(segment
		(start 298.483528 -294.121332)
		(end 298.07535 -294.121332)
		(width 0.18288)
		(layer "In11.Cu")
		(net "M_D_CPU0_SA_DQS_DP<7>")
	)
	(segment
		(start 307.36159 -290.07308)
		(end 306.526184 -290.908486)
		(width 0.18288)
		(layer "In11.Cu")
		(net "M_D_CPU0_SA_DQS_DP<7>")
	)
	(segment
		(start 305.849782 -290.908486)
		(end 304.548794 -292.209474)
		(width 0.18288)
		(layer "In11.Cu")
		(net "M_D_CPU0_SA_DQS_DP<7>")
	)
	(segment
		(start 292.231826 -294.307006)
		(end 291.795962 -294.74287)
		(width 0.18288)
		(layer "In11.Cu")
		(net "M_D_CPU0_SA_DQS_DP<7>")
	)
	(segment
		(start 291.795962 -294.74287)
		(end 291.336222 -294.74287)
		(width 0.18288)
		(layer "In11.Cu")
		(net "M_D_CPU0_SA_DQS_DP<7>")
	)
	(segment
		(start 294.713914 -294.641016)
		(end 294.442642 -294.912288)
		(width 0.18288)
		(layer "In11.Cu")
		(net "M_D_CPU0_SA_DQS_DP<7>")
	)
	(segment
		(start 331.221334 -274.844764)
		(end 331.087984 -274.844764)
		(width 0.088646)
		(layer "In11.Cu")
		(net "M_D_CPU0_SA_DQS_DP<7>")
	)
	(segment
		(start 346.735146 -272.140934)
		(end 346.720414 -272.14957)
		(width 0.088646)
		(layer "In11.Cu")
		(net "M_D_CPU0_SA_DQS_DP<7>")
	)
	(arc
		(start 345.78036 -272.14957)
		(mid 345.593162 -272.199713)
		(end 345.405964 -272.14957)
		(width 0.088646)
		(layer "In11.Cu")
		(net "M_D_CPU0_SA_DQS_DP<7>")
	)
	(arc
		(start 342.961214 -272.14957)
		(mid 342.774016 -272.199713)
		(end 342.586818 -272.14957)
		(width 0.088646)
		(layer "In11.Cu")
		(net "M_D_CPU0_SA_DQS_DP<7>")
	)
	(arc
		(start 335.44256 -272.14957)
		(mid 335.255362 -272.199713)
		(end 335.068164 -272.14957)
		(width 0.088646)
		(layer "In11.Cu")
		(net "M_D_CPU0_SA_DQS_DP<7>")
	)
	(arc
		(start 333.188564 -272.14957)
		(mid 333.052321 -272.093124)
		(end 332.906116 -272.073878)
		(width 0.088646)
		(layer "In11.Cu")
		(net "M_D_CPU0_SA_DQS_DP<7>")
	)
	(arc
		(start 344.466418 -272.14957)
		(mid 344.192189 -272.073645)
		(end 343.915746 -272.140934)
		(width 0.088646)
		(layer "In11.Cu")
		(net "M_D_CPU0_SA_DQS_DP<7>")
	)
	(arc
		(start 334.50276 -272.14957)
		(mid 334.315562 -272.199713)
		(end 334.128364 -272.14957)
		(width 0.088646)
		(layer "In11.Cu")
		(net "M_D_CPU0_SA_DQS_DP<7>")
	)
	(arc
		(start 341.647018 -272.14957)
		(mid 341.372789 -272.073645)
		(end 341.096346 -272.140934)
		(width 0.088646)
		(layer "In11.Cu")
		(net "M_D_CPU0_SA_DQS_DP<7>")
	)
	(arc
		(start 340.707218 -272.14957)
		(mid 340.432989 -272.073645)
		(end 340.156546 -272.140934)
		(width 0.088646)
		(layer "In11.Cu")
		(net "M_D_CPU0_SA_DQS_DP<7>")
	)
	(arc
		(start 334.128364 -272.14957)
		(mid 333.845662 -272.073828)
		(end 333.56296 -272.14957)
		(width 0.088646)
		(layer "In11.Cu")
		(net "M_D_CPU0_SA_DQS_DP<7>")
	)
	(arc
		(start 343.526618 -272.14957)
		(mid 343.252389 -272.073645)
		(end 342.975946 -272.140934)
		(width 0.088646)
		(layer "In11.Cu")
		(net "M_D_CPU0_SA_DQS_DP<7>")
	)
	(arc
		(start 337.887564 -272.14957)
		(mid 337.611005 -272.073861)
		(end 337.332828 -272.143474)
		(width 0.088646)
		(layer "In11.Cu")
		(net "M_D_CPU0_SA_DQS_DP<7>")
	)
	(arc
		(start 342.021414 -272.14957)
		(mid 341.834216 -272.199713)
		(end 341.647018 -272.14957)
		(width 0.088646)
		(layer "In11.Cu")
		(net "M_D_CPU0_SA_DQS_DP<7>")
	)
	(arc
		(start 341.081614 -272.14957)
		(mid 340.894416 -272.199713)
		(end 340.707218 -272.14957)
		(width 0.088646)
		(layer "In11.Cu")
		(net "M_D_CPU0_SA_DQS_DP<7>")
	)
	(arc
		(start 333.56296 -272.14957)
		(mid 333.375762 -272.199713)
		(end 333.188564 -272.14957)
		(width 0.088646)
		(layer "In11.Cu")
		(net "M_D_CPU0_SA_DQS_DP<7>")
	)
	(arc
		(start 348.501716 -272.552668)
		(mid 348.194858 -272.132882)
		(end 347.674946 -272.140934)
		(width 0.088646)
		(layer "In11.Cu")
		(net "M_D_CPU0_SA_DQS_DP<7>")
	)
	(arc
		(start 347.285818 -272.14957)
		(mid 347.011589 -272.073645)
		(end 346.735146 -272.140934)
		(width 0.088646)
		(layer "In11.Cu")
		(net "M_D_CPU0_SA_DQS_DP<7>")
	)
	(arc
		(start 336.38236 -272.14957)
		(mid 336.195162 -272.199713)
		(end 336.007964 -272.14957)
		(width 0.088646)
		(layer "In11.Cu")
		(net "M_D_CPU0_SA_DQS_DP<7>")
	)
	(arc
		(start 336.937604 -272.143474)
		(mid 336.659172 -272.07366)
		(end 336.38236 -272.14957)
		(width 0.088646)
		(layer "In11.Cu")
		(net "M_D_CPU0_SA_DQS_DP<7>")
	)
	(arc
		(start 335.053432 -272.140934)
		(mid 334.776991 -272.073768)
		(end 334.50276 -272.14957)
		(width 0.088646)
		(layer "In11.Cu")
		(net "M_D_CPU0_SA_DQS_DP<7>")
	)
	(arc
		(start 345.39555 -272.143474)
		(mid 345.117372 -272.073782)
		(end 344.840814 -272.14957)
		(width 0.088646)
		(layer "In11.Cu")
		(net "M_D_CPU0_SA_DQS_DP<7>")
	)
	(arc
		(start 348.50451 -272.574004)
		(mid 348.503215 -272.563323)
		(end 348.501716 -272.552668)
		(width 0.088646)
		(layer "In11.Cu")
		(net "M_D_CPU0_SA_DQS_DP<7>")
	)
	(arc
		(start 343.901014 -272.14957)
		(mid 343.713816 -272.199713)
		(end 343.526618 -272.14957)
		(width 0.088646)
		(layer "In11.Cu")
		(net "M_D_CPU0_SA_DQS_DP<7>")
	)
	(arc
		(start 342.586818 -272.14957)
		(mid 342.312589 -272.073645)
		(end 342.036146 -272.140934)
		(width 0.088646)
		(layer "In11.Cu")
		(net "M_D_CPU0_SA_DQS_DP<7>")
	)
	(arc
		(start 344.840814 -272.14957)
		(mid 344.653616 -272.199713)
		(end 344.466418 -272.14957)
		(width 0.088646)
		(layer "In11.Cu")
		(net "M_D_CPU0_SA_DQS_DP<7>")
	)
	(arc
		(start 347.660214 -272.14957)
		(mid 347.473016 -272.199713)
		(end 347.285818 -272.14957)
		(width 0.088646)
		(layer "In11.Cu")
		(net "M_D_CPU0_SA_DQS_DP<7>")
	)
	(arc
		(start 346.346018 -272.14957)
		(mid 346.069205 -272.073734)
		(end 345.790774 -272.143474)
		(width 0.088646)
		(layer "In11.Cu")
		(net "M_D_CPU0_SA_DQS_DP<7>")
	)
	(arc
		(start 339.20176 -272.14957)
		(mid 339.014562 -272.199713)
		(end 338.827364 -272.14957)
		(width 0.088646)
		(layer "In11.Cu")
		(net "M_D_CPU0_SA_DQS_DP<7>")
	)
	(arc
		(start 337.322414 -272.14957)
		(mid 337.135216 -272.199713)
		(end 336.948018 -272.14957)
		(width 0.088646)
		(layer "In11.Cu")
		(net "M_D_CPU0_SA_DQS_DP<7>")
	)
	(arc
		(start 340.141814 -272.14957)
		(mid 339.954616 -272.199713)
		(end 339.767418 -272.14957)
		(width 0.088646)
		(layer "In11.Cu")
		(net "M_D_CPU0_SA_DQS_DP<7>")
	)
	(arc
		(start 346.720414 -272.14957)
		(mid 346.533216 -272.199713)
		(end 346.346018 -272.14957)
		(width 0.088646)
		(layer "In11.Cu")
		(net "M_D_CPU0_SA_DQS_DP<7>")
	)
	(arc
		(start 339.767418 -272.14957)
		(mid 339.490605 -272.073734)
		(end 339.212174 -272.143474)
		(width 0.088646)
		(layer "In11.Cu")
		(net "M_D_CPU0_SA_DQS_DP<7>")
	)
	(arc
		(start 338.812632 -272.140934)
		(mid 338.536191 -272.073768)
		(end 338.26196 -272.14957)
		(width 0.088646)
		(layer "In11.Cu")
		(net "M_D_CPU0_SA_DQS_DP<7>")
	)
	(arc
		(start 338.26196 -272.14957)
		(mid 338.074762 -272.199713)
		(end 337.887564 -272.14957)
		(width 0.088646)
		(layer "In11.Cu")
		(net "M_D_CPU0_SA_DQS_DP<7>")
	)
	(arc
		(start 336.007964 -272.14957)
		(mid 335.725262 -272.073828)
		(end 335.44256 -272.14957)
		(width 0.088646)
		(layer "In11.Cu")
		(net "M_D_CPU0_SA_DQS_DP<7>")
	)
	(segment
		(start 265.227816 -301.702978)
		(end 264.966704 -301.441866)
		(width 0.20066)
		(layer "F.Cu")
		(net "M_D_CPU0_SA_DQS_DP<6>")
	)
	(segment
		(start 265.732768 -301.702978)
		(end 265.227816 -301.702978)
		(width 0.20066)
		(layer "F.Cu")
		(net "M_D_CPU0_SA_DQS_DP<6>")
	)
	(segment
		(start 261.673086 -301.705518)
		(end 261.250684 -302.12792)
		(width 0.20066)
		(layer "F.Cu")
		(net "M_D_CPU0_SA_DQS_DP<6>")
	)
	(segment
		(start 262.505952 -301.441866)
		(end 262.50011 -301.436024)
		(width 0.101854)
		(layer "F.Cu")
		(net "M_D_CPU0_SA_DQS_DP<6>")
	)
	(segment
		(start 262.746744 -301.441866)
		(end 262.505952 -301.441866)
		(width 0.101854)
		(layer "F.Cu")
		(net "M_D_CPU0_SA_DQS_DP<6>")
	)
	(segment
		(start 268.829282 -301.866808)
		(end 267.724382 -301.866808)
		(width 0.20066)
		(layer "F.Cu")
		(net "M_D_CPU0_SA_DQS_DP<6>")
	)
	(segment
		(start 266.368784 -302.12792)
		(end 265.732768 -301.702978)
		(width 0.20066)
		(layer "F.Cu")
		(net "M_D_CPU0_SA_DQS_DP<6>")
	)
	(segment
		(start 266.973304 -302.12792)
		(end 266.368784 -302.12792)
		(width 0.20066)
		(layer "F.Cu")
		(net "M_D_CPU0_SA_DQS_DP<6>")
	)
	(segment
		(start 260.655308 -301.866808)
		(end 260.180582 -301.866808)
		(width 0.20066)
		(layer "F.Cu")
		(net "M_D_CPU0_SA_DQS_DP<6>")
	)
	(segment
		(start 264.825226 -301.441866)
		(end 262.746744 -301.441866)
		(width 0.1016)
		(layer "F.Cu")
		(net "M_D_CPU0_SA_DQS_DP<6>")
	)
	(segment
		(start 262.302752 -301.436024)
		(end 262.033258 -301.705518)
		(width 0.20066)
		(layer "F.Cu")
		(net "M_D_CPU0_SA_DQS_DP<6>")
	)
	(segment
		(start 260.91642 -302.12792)
		(end 260.655308 -301.866808)
		(width 0.20066)
		(layer "F.Cu")
		(net "M_D_CPU0_SA_DQS_DP<6>")
	)
	(segment
		(start 261.250684 -302.12792)
		(end 260.91642 -302.12792)
		(width 0.20066)
		(layer "F.Cu")
		(net "M_D_CPU0_SA_DQS_DP<6>")
	)
	(segment
		(start 262.50011 -301.436024)
		(end 262.302752 -301.436024)
		(width 0.20066)
		(layer "F.Cu")
		(net "M_D_CPU0_SA_DQS_DP<6>")
	)
	(segment
		(start 262.033258 -301.705518)
		(end 261.673086 -301.705518)
		(width 0.20066)
		(layer "F.Cu")
		(net "M_D_CPU0_SA_DQS_DP<6>")
	)
	(segment
		(start 267.234416 -301.866808)
		(end 266.973304 -302.12792)
		(width 0.20066)
		(layer "F.Cu")
		(net "M_D_CPU0_SA_DQS_DP<6>")
	)
	(segment
		(start 267.724382 -301.866808)
		(end 267.234416 -301.866808)
		(width 0.20066)
		(layer "F.Cu")
		(net "M_D_CPU0_SA_DQS_DP<6>")
	)
	(segment
		(start 264.966704 -301.441866)
		(end 264.825226 -301.441866)
		(width 0.20066)
		(layer "F.Cu")
		(net "M_D_CPU0_SA_DQS_DP<6>")
	)
	(arc
		(start 348.882716 -276.986492)
		(mid 348.882652 -277.254462)
		(end 348.882462 -277.522432)
		(width 0.20066)
		(layer "F.Cu")
		(net "M_D_CPU0_SA_DQS_DP<6>")
	)
	(segment
		(start 338.827364 -277.032974)
		(end 338.812632 -277.024338)
		(width 0.088646)
		(layer "In11.Cu")
		(net "M_D_CPU0_SA_DQS_DP<6>")
	)
	(segment
		(start 339.212174 -277.026878)
		(end 339.20176 -277.032974)
		(width 0.088646)
		(layer "In11.Cu")
		(net "M_D_CPU0_SA_DQS_DP<6>")
	)
	(segment
		(start 299.234606 -306.540916)
		(end 298.813982 -306.540916)
		(width 0.18288)
		(layer "In11.Cu")
		(net "M_D_CPU0_SA_DQS_DP<6>")
	)
	(segment
		(start 344.851228 -277.026878)
		(end 344.840814 -277.032974)
		(width 0.088646)
		(layer "In11.Cu")
		(net "M_D_CPU0_SA_DQS_DP<6>")
	)
	(segment
		(start 340.156546 -277.024338)
		(end 340.141814 -277.032974)
		(width 0.088646)
		(layer "In11.Cu")
		(net "M_D_CPU0_SA_DQS_DP<6>")
	)
	(segment
		(start 278.028654 -308.274466)
		(end 277.525226 -308.274466)
		(width 0.18288)
		(layer "In11.Cu")
		(net "M_D_CPU0_SA_DQS_DP<6>")
	)
	(segment
		(start 291.70122 -307.639466)
		(end 288.56305 -307.639466)
		(width 0.18288)
		(layer "In11.Cu")
		(net "M_D_CPU0_SA_DQS_DP<6>")
	)
	(segment
		(start 332.38948 -280.179018)
		(end 331.597 -280.971498)
		(width 0.088646)
		(layer "In11.Cu")
		(net "M_D_CPU0_SA_DQS_DP<6>")
	)
	(segment
		(start 330.490068 -281.114246)
		(end 319.894204 -291.71011)
		(width 0.18288)
		(layer "In11.Cu")
		(net "M_D_CPU0_SA_DQS_DP<6>")
	)
	(segment
		(start 347.674946 -277.024338)
		(end 347.660214 -277.032974)
		(width 0.088646)
		(layer "In11.Cu")
		(net "M_D_CPU0_SA_DQS_DP<6>")
	)
	(segment
		(start 307.38699 -301.050706)
		(end 306.60213 -301.835566)
		(width 0.18288)
		(layer "In11.Cu")
		(net "M_D_CPU0_SA_DQS_DP<6>")
	)
	(segment
		(start 297.788584 -306.794154)
		(end 296.913046 -307.669692)
		(width 0.18288)
		(layer "In11.Cu")
		(net "M_D_CPU0_SA_DQS_DP<6>")
	)
	(segment
		(start 280.006806 -307.391054)
		(end 279.626314 -307.391054)
		(width 0.18288)
		(layer "In11.Cu")
		(net "M_D_CPU0_SA_DQS_DP<6>")
	)
	(segment
		(start 332.38948 -279.977596)
		(end 332.38948 -280.179018)
		(width 0.088646)
		(layer "In11.Cu")
		(net "M_D_CPU0_SA_DQS_DP<6>")
	)
	(segment
		(start 302.297592 -304.929286)
		(end 300.394878 -306.832)
		(width 0.18288)
		(layer "In11.Cu")
		(net "M_D_CPU0_SA_DQS_DP<6>")
	)
	(segment
		(start 274.60575 -304.388266)
		(end 273.944334 -304.388266)
		(width 0.18288)
		(layer "In11.Cu")
		(net "M_D_CPU0_SA_DQS_DP<6>")
	)
	(segment
		(start 334.035146 -277.741634)
		(end 333.516986 -278.259794)
		(width 0.088646)
		(layer "In11.Cu")
		(net "M_D_CPU0_SA_DQS_DP<6>")
	)
	(segment
		(start 309.770526 -299.741082)
		(end 309.47487 -300.036738)
		(width 0.18288)
		(layer "In11.Cu")
		(net "M_D_CPU0_SA_DQS_DP<6>")
	)
	(segment
		(start 299.52569 -306.832)
		(end 299.234606 -306.540916)
		(width 0.18288)
		(layer "In11.Cu")
		(net "M_D_CPU0_SA_DQS_DP<6>")
	)
	(segment
		(start 309.47487 -300.036738)
		(end 308.682136 -300.036738)
		(width 0.18288)
		(layer "In11.Cu")
		(net "M_D_CPU0_SA_DQS_DP<6>")
	)
	(segment
		(start 270.622776 -302.550068)
		(end 269.985998 -302.550068)
		(width 0.18288)
		(layer "In11.Cu")
		(net "M_D_CPU0_SA_DQS_DP<6>")
	)
	(segment
		(start 313.311794 -299.18279)
		(end 312.506106 -299.988478)
		(width 0.18288)
		(layer "In11.Cu")
		(net "M_D_CPU0_SA_DQS_DP<6>")
	)
	(segment
		(start 287.726882 -306.803298)
		(end 284.385004 -306.803298)
		(width 0.18288)
		(layer "In11.Cu")
		(net "M_D_CPU0_SA_DQS_DP<6>")
	)
	(segment
		(start 341.096346 -277.024338)
		(end 341.081614 -277.032974)
		(width 0.088646)
		(layer "In11.Cu")
		(net "M_D_CPU0_SA_DQS_DP<6>")
	)
	(segment
		(start 273.42592 -304.173382)
		(end 272.638012 -303.385728)
		(width 0.18288)
		(layer "In11.Cu")
		(net "M_D_CPU0_SA_DQS_DP<6>")
	)
	(segment
		(start 305.012598 -301.835566)
		(end 303.497488 -303.350676)
		(width 0.18288)
		(layer "In11.Cu")
		(net "M_D_CPU0_SA_DQS_DP<6>")
	)
	(segment
		(start 310.510174 -299.988478)
		(end 310.262778 -299.741082)
		(width 0.18288)
		(layer "In11.Cu")
		(net "M_D_CPU0_SA_DQS_DP<6>")
	)
	(segment
		(start 316.172342 -297.937936)
		(end 314.943998 -299.16628)
		(width 0.18288)
		(layer "In11.Cu")
		(net "M_D_CPU0_SA_DQS_DP<6>")
	)
	(segment
		(start 273.944334 -304.388266)
		(end 273.42592 -304.173382)
		(width 0.18288)
		(layer "In11.Cu")
		(net "M_D_CPU0_SA_DQS_DP<6>")
	)
	(segment
		(start 303.497488 -303.350676)
		(end 303.497488 -304.284888)
		(width 0.18288)
		(layer "In11.Cu")
		(net "M_D_CPU0_SA_DQS_DP<6>")
	)
	(segment
		(start 302.85309 -304.929286)
		(end 302.297592 -304.929286)
		(width 0.18288)
		(layer "In11.Cu")
		(net "M_D_CPU0_SA_DQS_DP<6>")
	)
	(segment
		(start 331.597 -280.971498)
		(end 331.512672 -280.971498)
		(width 0.088646)
		(layer "In11.Cu")
		(net "M_D_CPU0_SA_DQS_DP<6>")
	)
	(segment
		(start 331.369924 -281.114246)
		(end 330.490068 -281.114246)
		(width 0.18288)
		(layer "In11.Cu")
		(net "M_D_CPU0_SA_DQS_DP<6>")
	)
	(segment
		(start 283.441394 -306.818792)
		(end 282.836874 -306.818792)
		(width 0.18288)
		(layer "In11.Cu")
		(net "M_D_CPU0_SA_DQS_DP<6>")
	)
	(segment
		(start 269.581376 -302.145446)
		(end 269.10792 -302.145446)
		(width 0.18288)
		(layer "In11.Cu")
		(net "M_D_CPU0_SA_DQS_DP<6>")
	)
	(segment
		(start 336.397092 -277.024338)
		(end 336.38236 -277.032974)
		(width 0.088646)
		(layer "In11.Cu")
		(net "M_D_CPU0_SA_DQS_DP<6>")
	)
	(segment
		(start 348.882462 -277.522432)
		(end 348.569788 -277.522432)
		(width 0.088646)
		(layer "In11.Cu")
		(net "M_D_CPU0_SA_DQS_DP<6>")
	)
	(segment
		(start 284.385004 -306.803298)
		(end 284.122622 -306.540916)
		(width 0.18288)
		(layer "In11.Cu")
		(net "M_D_CPU0_SA_DQS_DP<6>")
	)
	(segment
		(start 288.56305 -307.639466)
		(end 287.726882 -306.803298)
		(width 0.18288)
		(layer "In11.Cu")
		(net "M_D_CPU0_SA_DQS_DP<6>")
	)
	(segment
		(start 298.560744 -306.794154)
		(end 297.788584 -306.794154)
		(width 0.18288)
		(layer "In11.Cu")
		(net "M_D_CPU0_SA_DQS_DP<6>")
	)
	(segment
		(start 342.975946 -277.024338)
		(end 342.961214 -277.032974)
		(width 0.088646)
		(layer "In11.Cu")
		(net "M_D_CPU0_SA_DQS_DP<6>")
	)
	(segment
		(start 313.614308 -299.18279)
		(end 313.311794 -299.18279)
		(width 0.18288)
		(layer "In11.Cu")
		(net "M_D_CPU0_SA_DQS_DP<6>")
	)
	(segment
		(start 333.516986 -278.259794)
		(end 333.516986 -278.85009)
		(width 0.088646)
		(layer "In11.Cu")
		(net "M_D_CPU0_SA_DQS_DP<6>")
	)
	(segment
		(start 348.569788 -277.522432)
		(end 348.504256 -277.4569)
		(width 0.088646)
		(layer "In11.Cu")
		(net "M_D_CPU0_SA_DQS_DP<6>")
	)
	(segment
		(start 293.691818 -307.688234)
		(end 293.01567 -307.012086)
		(width 0.18288)
		(layer "In11.Cu")
		(net "M_D_CPU0_SA_DQS_DP<6>")
	)
	(segment
		(start 303.497488 -304.284888)
		(end 302.85309 -304.929286)
		(width 0.18288)
		(layer "In11.Cu")
		(net "M_D_CPU0_SA_DQS_DP<6>")
	)
	(segment
		(start 295.372028 -307.669692)
		(end 295.09339 -307.391054)
		(width 0.18288)
		(layer "In11.Cu")
		(net "M_D_CPU0_SA_DQS_DP<6>")
	)
	(segment
		(start 334.85328 -277.741634)
		(end 334.035146 -277.741634)
		(width 0.088646)
		(layer "In11.Cu")
		(net "M_D_CPU0_SA_DQS_DP<6>")
	)
	(segment
		(start 345.790774 -277.026878)
		(end 345.78036 -277.032974)
		(width 0.088646)
		(layer "In11.Cu")
		(net "M_D_CPU0_SA_DQS_DP<6>")
	)
	(segment
		(start 333.516986 -278.85009)
		(end 332.38948 -279.977596)
		(width 0.088646)
		(layer "In11.Cu")
		(net "M_D_CPU0_SA_DQS_DP<6>")
	)
	(segment
		(start 308.682136 -300.036738)
		(end 307.668168 -301.050706)
		(width 0.18288)
		(layer "In11.Cu")
		(net "M_D_CPU0_SA_DQS_DP<6>")
	)
	(segment
		(start 296.913046 -307.669692)
		(end 295.372028 -307.669692)
		(width 0.18288)
		(layer "In11.Cu")
		(net "M_D_CPU0_SA_DQS_DP<6>")
	)
	(segment
		(start 281.99461 -307.661056)
		(end 280.276808 -307.661056)
		(width 0.18288)
		(layer "In11.Cu")
		(net "M_D_CPU0_SA_DQS_DP<6>")
	)
	(segment
		(start 278.655272 -307.647848)
		(end 278.028654 -308.274466)
		(width 0.18288)
		(layer "In11.Cu")
		(net "M_D_CPU0_SA_DQS_DP<6>")
	)
	(segment
		(start 312.506106 -299.988478)
		(end 310.510174 -299.988478)
		(width 0.18288)
		(layer "In11.Cu")
		(net "M_D_CPU0_SA_DQS_DP<6>")
	)
	(segment
		(start 336.041492 -277.17877)
		(end 335.547462 -277.50897)
		(width 0.088646)
		(layer "In11.Cu")
		(net "M_D_CPU0_SA_DQS_DP<6>")
	)
	(segment
		(start 310.262778 -299.741082)
		(end 309.770526 -299.741082)
		(width 0.18288)
		(layer "In11.Cu")
		(net "M_D_CPU0_SA_DQS_DP<6>")
	)
	(segment
		(start 346.735146 -277.024338)
		(end 346.720414 -277.032974)
		(width 0.088646)
		(layer "In11.Cu")
		(net "M_D_CPU0_SA_DQS_DP<6>")
	)
	(segment
		(start 294.707818 -307.391054)
		(end 294.410638 -307.688234)
		(width 0.18288)
		(layer "In11.Cu")
		(net "M_D_CPU0_SA_DQS_DP<6>")
	)
	(segment
		(start 284.122622 -306.540916)
		(end 283.71927 -306.540916)
		(width 0.18288)
		(layer "In11.Cu")
		(net "M_D_CPU0_SA_DQS_DP<6>")
	)
	(segment
		(start 306.60213 -301.835566)
		(end 305.012598 -301.835566)
		(width 0.18288)
		(layer "In11.Cu")
		(net "M_D_CPU0_SA_DQS_DP<6>")
	)
	(segment
		(start 280.276808 -307.661056)
		(end 280.006806 -307.391054)
		(width 0.18288)
		(layer "In11.Cu")
		(net "M_D_CPU0_SA_DQS_DP<6>")
	)
	(segment
		(start 279.36952 -307.647848)
		(end 278.655272 -307.647848)
		(width 0.18288)
		(layer "In11.Cu")
		(net "M_D_CPU0_SA_DQS_DP<6>")
	)
	(segment
		(start 294.410638 -307.688234)
		(end 293.691818 -307.688234)
		(width 0.18288)
		(layer "In11.Cu")
		(net "M_D_CPU0_SA_DQS_DP<6>")
	)
	(segment
		(start 314.28563 -298.895008)
		(end 313.90209 -298.895008)
		(width 0.18288)
		(layer "In11.Cu")
		(net "M_D_CPU0_SA_DQS_DP<6>")
	)
	(segment
		(start 316.172342 -296.171112)
		(end 316.172342 -297.937936)
		(width 0.18288)
		(layer "In11.Cu")
		(net "M_D_CPU0_SA_DQS_DP<6>")
	)
	(segment
		(start 277.525226 -308.274466)
		(end 276.426422 -307.819044)
		(width 0.18288)
		(layer "In11.Cu")
		(net "M_D_CPU0_SA_DQS_DP<6>")
	)
	(segment
		(start 275.899626 -306.998878)
		(end 275.899626 -305.682142)
		(width 0.18288)
		(layer "In11.Cu")
		(net "M_D_CPU0_SA_DQS_DP<6>")
	)
	(segment
		(start 295.09339 -307.391054)
		(end 294.707818 -307.391054)
		(width 0.18288)
		(layer "In11.Cu")
		(net "M_D_CPU0_SA_DQS_DP<6>")
	)
	(segment
		(start 314.556902 -299.16628)
		(end 314.28563 -298.895008)
		(width 0.18288)
		(layer "In11.Cu")
		(net "M_D_CPU0_SA_DQS_DP<6>")
	)
	(segment
		(start 272.638012 -303.385728)
		(end 270.622776 -302.550068)
		(width 0.18288)
		(layer "In11.Cu")
		(net "M_D_CPU0_SA_DQS_DP<6>")
	)
	(segment
		(start 298.813982 -306.540916)
		(end 298.560744 -306.794154)
		(width 0.18288)
		(layer "In11.Cu")
		(net "M_D_CPU0_SA_DQS_DP<6>")
	)
	(segment
		(start 343.915746 -277.024338)
		(end 343.901014 -277.032974)
		(width 0.088646)
		(layer "In11.Cu")
		(net "M_D_CPU0_SA_DQS_DP<6>")
	)
	(segment
		(start 331.512672 -280.971498)
		(end 331.369924 -281.114246)
		(width 0.18288)
		(layer "In11.Cu")
		(net "M_D_CPU0_SA_DQS_DP<6>")
	)
	(segment
		(start 282.836874 -306.818792)
		(end 281.99461 -307.661056)
		(width 0.18288)
		(layer "In11.Cu")
		(net "M_D_CPU0_SA_DQS_DP<6>")
	)
	(segment
		(start 314.943998 -299.16628)
		(end 314.556902 -299.16628)
		(width 0.18288)
		(layer "In11.Cu")
		(net "M_D_CPU0_SA_DQS_DP<6>")
	)
	(segment
		(start 283.71927 -306.540916)
		(end 283.441394 -306.818792)
		(width 0.18288)
		(layer "In11.Cu")
		(net "M_D_CPU0_SA_DQS_DP<6>")
	)
	(segment
		(start 269.10792 -302.145446)
		(end 268.829282 -301.866808)
		(width 0.18288)
		(layer "In11.Cu")
		(net "M_D_CPU0_SA_DQS_DP<6>")
	)
	(segment
		(start 313.90209 -298.895008)
		(end 313.614308 -299.18279)
		(width 0.18288)
		(layer "In11.Cu")
		(net "M_D_CPU0_SA_DQS_DP<6>")
	)
	(segment
		(start 276.426422 -307.819044)
		(end 276.107652 -307.500528)
		(width 0.18288)
		(layer "In11.Cu")
		(net "M_D_CPU0_SA_DQS_DP<6>")
	)
	(segment
		(start 319.894204 -291.71011)
		(end 319.894204 -292.44925)
		(width 0.18288)
		(layer "In11.Cu")
		(net "M_D_CPU0_SA_DQS_DP<6>")
	)
	(segment
		(start 319.894204 -292.44925)
		(end 316.172342 -296.171112)
		(width 0.18288)
		(layer "In11.Cu")
		(net "M_D_CPU0_SA_DQS_DP<6>")
	)
	(segment
		(start 342.036146 -277.024338)
		(end 342.021414 -277.032974)
		(width 0.088646)
		(layer "In11.Cu")
		(net "M_D_CPU0_SA_DQS_DP<6>")
	)
	(segment
		(start 292.3286 -307.012086)
		(end 291.70122 -307.639466)
		(width 0.18288)
		(layer "In11.Cu")
		(net "M_D_CPU0_SA_DQS_DP<6>")
	)
	(segment
		(start 279.626314 -307.391054)
		(end 279.36952 -307.647848)
		(width 0.18288)
		(layer "In11.Cu")
		(net "M_D_CPU0_SA_DQS_DP<6>")
	)
	(segment
		(start 269.985998 -302.550068)
		(end 269.581376 -302.145446)
		(width 0.18288)
		(layer "In11.Cu")
		(net "M_D_CPU0_SA_DQS_DP<6>")
	)
	(segment
		(start 293.01567 -307.012086)
		(end 292.3286 -307.012086)
		(width 0.18288)
		(layer "In11.Cu")
		(net "M_D_CPU0_SA_DQS_DP<6>")
	)
	(segment
		(start 300.394878 -306.832)
		(end 299.52569 -306.832)
		(width 0.18288)
		(layer "In11.Cu")
		(net "M_D_CPU0_SA_DQS_DP<6>")
	)
	(segment
		(start 276.107652 -307.500528)
		(end 275.899626 -306.998878)
		(width 0.18288)
		(layer "In11.Cu")
		(net "M_D_CPU0_SA_DQS_DP<6>")
	)
	(segment
		(start 275.899626 -305.682142)
		(end 274.60575 -304.388266)
		(width 0.18288)
		(layer "In11.Cu")
		(net "M_D_CPU0_SA_DQS_DP<6>")
	)
	(segment
		(start 307.668168 -301.050706)
		(end 307.38699 -301.050706)
		(width 0.18288)
		(layer "In11.Cu")
		(net "M_D_CPU0_SA_DQS_DP<6>")
	)
	(arc
		(start 336.38236 -277.032974)
		(mid 336.334131 -277.056466)
		(end 336.283046 -277.072852)
		(width 0.088646)
		(layer "In11.Cu")
		(net "M_D_CPU0_SA_DQS_DP<6>")
	)
	(arc
		(start 347.660214 -277.032974)
		(mid 347.473016 -277.083117)
		(end 347.285818 -277.032974)
		(width 0.088646)
		(layer "In11.Cu")
		(net "M_D_CPU0_SA_DQS_DP<6>")
	)
	(arc
		(start 337.32216 -277.032974)
		(mid 337.134962 -277.083117)
		(end 336.947764 -277.032974)
		(width 0.088646)
		(layer "In11.Cu")
		(net "M_D_CPU0_SA_DQS_DP<6>")
	)
	(arc
		(start 348.225618 -277.032974)
		(mid 347.951419 -276.957139)
		(end 347.674946 -277.024338)
		(width 0.088646)
		(layer "In11.Cu")
		(net "M_D_CPU0_SA_DQS_DP<6>")
	)
	(arc
		(start 348.501462 -277.435818)
		(mid 348.409301 -277.203046)
		(end 348.225618 -277.032974)
		(width 0.088646)
		(layer "In11.Cu")
		(net "M_D_CPU0_SA_DQS_DP<6>")
	)
	(arc
		(start 346.720414 -277.032974)
		(mid 346.533216 -277.083117)
		(end 346.346018 -277.032974)
		(width 0.088646)
		(layer "In11.Cu")
		(net "M_D_CPU0_SA_DQS_DP<6>")
	)
	(arc
		(start 347.285818 -277.032974)
		(mid 347.011619 -276.957139)
		(end 346.735146 -277.024338)
		(width 0.088646)
		(layer "In11.Cu")
		(net "M_D_CPU0_SA_DQS_DP<6>")
	)
	(arc
		(start 336.947764 -277.032974)
		(mid 336.673535 -276.957049)
		(end 336.397092 -277.024338)
		(width 0.088646)
		(layer "In11.Cu")
		(net "M_D_CPU0_SA_DQS_DP<6>")
	)
	(arc
		(start 341.647018 -277.032974)
		(mid 341.372819 -276.957139)
		(end 341.096346 -277.024338)
		(width 0.088646)
		(layer "In11.Cu")
		(net "M_D_CPU0_SA_DQS_DP<6>")
	)
	(arc
		(start 344.840814 -277.032974)
		(mid 344.653616 -277.083117)
		(end 344.466418 -277.032974)
		(width 0.088646)
		(layer "In11.Cu")
		(net "M_D_CPU0_SA_DQS_DP<6>")
	)
	(arc
		(start 339.20176 -277.032974)
		(mid 339.014562 -277.083117)
		(end 338.827364 -277.032974)
		(width 0.088646)
		(layer "In11.Cu")
		(net "M_D_CPU0_SA_DQS_DP<6>")
	)
	(arc
		(start 345.78036 -277.032974)
		(mid 345.593162 -277.083117)
		(end 345.405964 -277.032974)
		(width 0.088646)
		(layer "In11.Cu")
		(net "M_D_CPU0_SA_DQS_DP<6>")
	)
	(arc
		(start 344.466418 -277.032974)
		(mid 344.192219 -276.957139)
		(end 343.915746 -277.024338)
		(width 0.088646)
		(layer "In11.Cu")
		(net "M_D_CPU0_SA_DQS_DP<6>")
	)
	(arc
		(start 337.887564 -277.032974)
		(mid 337.604862 -276.957198)
		(end 337.32216 -277.032974)
		(width 0.088646)
		(layer "In11.Cu")
		(net "M_D_CPU0_SA_DQS_DP<6>")
	)
	(arc
		(start 342.961214 -277.032974)
		(mid 342.774016 -277.083117)
		(end 342.586818 -277.032974)
		(width 0.088646)
		(layer "In11.Cu")
		(net "M_D_CPU0_SA_DQS_DP<6>")
	)
	(arc
		(start 335.506822 -277.536402)
		(mid 335.195783 -277.689111)
		(end 334.85328 -277.741634)
		(width 0.088646)
		(layer "In11.Cu")
		(net "M_D_CPU0_SA_DQS_DP<6>")
	)
	(arc
		(start 343.526618 -277.032974)
		(mid 343.252419 -276.957139)
		(end 342.975946 -277.024338)
		(width 0.088646)
		(layer "In11.Cu")
		(net "M_D_CPU0_SA_DQS_DP<6>")
	)
	(arc
		(start 342.021414 -277.032974)
		(mid 341.834216 -277.083117)
		(end 341.647018 -277.032974)
		(width 0.088646)
		(layer "In11.Cu")
		(net "M_D_CPU0_SA_DQS_DP<6>")
	)
	(arc
		(start 335.547462 -277.50897)
		(mid 335.527069 -277.522577)
		(end 335.506822 -277.536402)
		(width 0.088646)
		(layer "In11.Cu")
		(net "M_D_CPU0_SA_DQS_DP<6>")
	)
	(arc
		(start 345.405964 -277.032974)
		(mid 345.129405 -276.957231)
		(end 344.851228 -277.026878)
		(width 0.088646)
		(layer "In11.Cu")
		(net "M_D_CPU0_SA_DQS_DP<6>")
	)
	(arc
		(start 338.812632 -277.024338)
		(mid 338.536157 -276.957018)
		(end 338.26196 -277.032974)
		(width 0.088646)
		(layer "In11.Cu")
		(net "M_D_CPU0_SA_DQS_DP<6>")
	)
	(arc
		(start 340.141814 -277.032974)
		(mid 339.954616 -277.083117)
		(end 339.767418 -277.032974)
		(width 0.088646)
		(layer "In11.Cu")
		(net "M_D_CPU0_SA_DQS_DP<6>")
	)
	(arc
		(start 341.081614 -277.032974)
		(mid 340.894416 -277.083117)
		(end 340.707218 -277.032974)
		(width 0.088646)
		(layer "In11.Cu")
		(net "M_D_CPU0_SA_DQS_DP<6>")
	)
	(arc
		(start 346.346018 -277.032974)
		(mid 346.069205 -276.957104)
		(end 345.790774 -277.026878)
		(width 0.088646)
		(layer "In11.Cu")
		(net "M_D_CPU0_SA_DQS_DP<6>")
	)
	(arc
		(start 336.283046 -277.072852)
		(mid 336.157611 -277.115187)
		(end 336.041492 -277.17877)
		(width 0.088646)
		(layer "In11.Cu")
		(net "M_D_CPU0_SA_DQS_DP<6>")
	)
	(arc
		(start 340.707218 -277.032974)
		(mid 340.433019 -276.957139)
		(end 340.156546 -277.024338)
		(width 0.088646)
		(layer "In11.Cu")
		(net "M_D_CPU0_SA_DQS_DP<6>")
	)
	(arc
		(start 342.586818 -277.032974)
		(mid 342.312619 -276.957139)
		(end 342.036146 -277.024338)
		(width 0.088646)
		(layer "In11.Cu")
		(net "M_D_CPU0_SA_DQS_DP<6>")
	)
	(arc
		(start 343.901014 -277.032974)
		(mid 343.713816 -277.083117)
		(end 343.526618 -277.032974)
		(width 0.088646)
		(layer "In11.Cu")
		(net "M_D_CPU0_SA_DQS_DP<6>")
	)
	(arc
		(start 338.26196 -277.032974)
		(mid 338.074762 -277.083117)
		(end 337.887564 -277.032974)
		(width 0.088646)
		(layer "In11.Cu")
		(net "M_D_CPU0_SA_DQS_DP<6>")
	)
	(arc
		(start 339.767418 -277.032974)
		(mid 339.490605 -276.957104)
		(end 339.212174 -277.026878)
		(width 0.088646)
		(layer "In11.Cu")
		(net "M_D_CPU0_SA_DQS_DP<6>")
	)
	(arc
		(start 348.504256 -277.4569)
		(mid 348.502958 -277.446346)
		(end 348.501462 -277.435818)
		(width 0.088646)
		(layer "In11.Cu")
		(net "M_D_CPU0_SA_DQS_DP<6>")
	)
	(segment
		(start 262.746744 -310.79186)
		(end 262.505952 -310.79186)
		(width 0.101854)
		(layer "F.Cu")
		(net "M_D_CPU0_SA_DQS_DP<5>")
	)
	(segment
		(start 265.227816 -311.052972)
		(end 264.966704 -310.79186)
		(width 0.20066)
		(layer "F.Cu")
		(net "M_D_CPU0_SA_DQS_DP<5>")
	)
	(segment
		(start 260.655308 -311.216802)
		(end 260.180582 -311.216802)
		(width 0.20066)
		(layer "F.Cu")
		(net "M_D_CPU0_SA_DQS_DP<5>")
	)
	(segment
		(start 268.829282 -311.216802)
		(end 267.724382 -311.216802)
		(width 0.20066)
		(layer "F.Cu")
		(net "M_D_CPU0_SA_DQS_DP<5>")
	)
	(segment
		(start 267.724382 -311.216802)
		(end 267.234416 -311.216802)
		(width 0.20066)
		(layer "F.Cu")
		(net "M_D_CPU0_SA_DQS_DP<5>")
	)
	(segment
		(start 261.673086 -311.055512)
		(end 261.250684 -311.477914)
		(width 0.20066)
		(layer "F.Cu")
		(net "M_D_CPU0_SA_DQS_DP<5>")
	)
	(segment
		(start 261.250684 -311.477914)
		(end 260.91642 -311.477914)
		(width 0.20066)
		(layer "F.Cu")
		(net "M_D_CPU0_SA_DQS_DP<5>")
	)
	(segment
		(start 262.50011 -310.786018)
		(end 262.302752 -310.786018)
		(width 0.20066)
		(layer "F.Cu")
		(net "M_D_CPU0_SA_DQS_DP<5>")
	)
	(segment
		(start 264.966704 -310.79186)
		(end 264.825226 -310.79186)
		(width 0.20066)
		(layer "F.Cu")
		(net "M_D_CPU0_SA_DQS_DP<5>")
	)
	(segment
		(start 262.302752 -310.786018)
		(end 262.033258 -311.055512)
		(width 0.20066)
		(layer "F.Cu")
		(net "M_D_CPU0_SA_DQS_DP<5>")
	)
	(segment
		(start 264.825226 -310.79186)
		(end 262.746744 -310.79186)
		(width 0.1016)
		(layer "F.Cu")
		(net "M_D_CPU0_SA_DQS_DP<5>")
	)
	(segment
		(start 267.234416 -311.216802)
		(end 266.973304 -311.477914)
		(width 0.20066)
		(layer "F.Cu")
		(net "M_D_CPU0_SA_DQS_DP<5>")
	)
	(segment
		(start 266.973304 -311.477914)
		(end 266.368784 -311.477914)
		(width 0.20066)
		(layer "F.Cu")
		(net "M_D_CPU0_SA_DQS_DP<5>")
	)
	(segment
		(start 262.033258 -311.055512)
		(end 261.673086 -311.055512)
		(width 0.20066)
		(layer "F.Cu")
		(net "M_D_CPU0_SA_DQS_DP<5>")
	)
	(segment
		(start 260.91642 -311.477914)
		(end 260.655308 -311.216802)
		(width 0.20066)
		(layer "F.Cu")
		(net "M_D_CPU0_SA_DQS_DP<5>")
	)
	(segment
		(start 262.505952 -310.79186)
		(end 262.50011 -310.786018)
		(width 0.101854)
		(layer "F.Cu")
		(net "M_D_CPU0_SA_DQS_DP<5>")
	)
	(segment
		(start 265.732768 -311.052972)
		(end 265.227816 -311.052972)
		(width 0.20066)
		(layer "F.Cu")
		(net "M_D_CPU0_SA_DQS_DP<5>")
	)
	(segment
		(start 266.368784 -311.477914)
		(end 265.732768 -311.052972)
		(width 0.20066)
		(layer "F.Cu")
		(net "M_D_CPU0_SA_DQS_DP<5>")
	)
	(arc
		(start 344.653362 -274.54479)
		(mid 344.653425 -274.81276)
		(end 344.653616 -275.08073)
		(width 0.20066)
		(layer "F.Cu")
		(net "M_D_CPU0_SA_DQS_DP<5>")
	)
	(segment
		(start 319.086992 -290.900866)
		(end 318.69888 -291.288978)
		(width 0.18288)
		(layer "In6.Cu")
		(net "M_D_CPU0_SA_DQS_DP<5>")
	)
	(segment
		(start 329.734926 -280.428954)
		(end 329.558904 -280.428954)
		(width 0.18288)
		(layer "In6.Cu")
		(net "M_D_CPU0_SA_DQS_DP<5>")
	)
	(segment
		(start 307.610256 -299.12564)
		(end 306.778914 -299.956982)
		(width 0.18288)
		(layer "In6.Cu")
		(net "M_D_CPU0_SA_DQS_DP<5>")
	)
	(segment
		(start 293.847774 -307.651404)
		(end 293.220902 -308.278276)
		(width 0.18288)
		(layer "In6.Cu")
		(net "M_D_CPU0_SA_DQS_DP<5>")
	)
	(segment
		(start 344.653108 -275.08073)
		(end 344.373962 -274.809966)
		(width 0.088646)
		(layer "In6.Cu")
		(net "M_D_CPU0_SA_DQS_DP<5>")
	)
	(segment
		(start 327.266808 -282.72105)
		(end 327.266808 -282.897072)
		(width 0.18288)
		(layer "In6.Cu")
		(net "M_D_CPU0_SA_DQS_DP<5>")
	)
	(segment
		(start 269.593568 -311.47639)
		(end 269.08887 -311.47639)
		(width 0.18288)
		(layer "In6.Cu")
		(net "M_D_CPU0_SA_DQS_DP<5>")
	)
	(segment
		(start 313.727084 -296.709592)
		(end 312.298588 -298.138088)
		(width 0.18288)
		(layer "In6.Cu")
		(net "M_D_CPU0_SA_DQS_DP<5>")
	)
	(segment
		(start 319.650872 -290.336986)
		(end 319.650872 -290.513008)
		(width 0.18288)
		(layer "In6.Cu")
		(net "M_D_CPU0_SA_DQS_DP<5>")
	)
	(segment
		(start 299.282358 -304.841656)
		(end 298.781724 -304.841656)
		(width 0.18288)
		(layer "In6.Cu")
		(net "M_D_CPU0_SA_DQS_DP<5>")
	)
	(segment
		(start 318.69888 -291.288978)
		(end 318.69888 -291.465)
		(width 0.18288)
		(layer "In6.Cu")
		(net "M_D_CPU0_SA_DQS_DP<5>")
	)
	(segment
		(start 304.707544 -302.285146)
		(end 304.321718 -302.285146)
		(width 0.18288)
		(layer "In6.Cu")
		(net "M_D_CPU0_SA_DQS_DP<5>")
	)
	(segment
		(start 272.408142 -311.737756)
		(end 269.854934 -311.737756)
		(width 0.18288)
		(layer "In6.Cu")
		(net "M_D_CPU0_SA_DQS_DP<5>")
	)
	(segment
		(start 304.321718 -302.285146)
		(end 303.038002 -303.568862)
		(width 0.18288)
		(layer "In6.Cu")
		(net "M_D_CPU0_SA_DQS_DP<5>")
	)
	(segment
		(start 280.022808 -310.79186)
		(end 279.618186 -310.79186)
		(width 0.18288)
		(layer "In6.Cu")
		(net "M_D_CPU0_SA_DQS_DP<5>")
	)
	(segment
		(start 336.86115 -276.214078)
		(end 336.85226 -276.219158)
		(width 0.088646)
		(layer "In6.Cu")
		(net "M_D_CPU0_SA_DQS_DP<5>")
	)
	(segment
		(start 283.694124 -312.491628)
		(end 283.444696 -312.741056)
		(width 0.18288)
		(layer "In6.Cu")
		(net "M_D_CPU0_SA_DQS_DP<5>")
	)
	(segment
		(start 292.7096 -308.278276)
		(end 291.379656 -309.60822)
		(width 0.18288)
		(layer "In6.Cu")
		(net "M_D_CPU0_SA_DQS_DP<5>")
	)
	(segment
		(start 315.997844 -294.76827)
		(end 314.056522 -296.709592)
		(width 0.18288)
		(layer "In6.Cu")
		(net "M_D_CPU0_SA_DQS_DP<5>")
	)
	(segment
		(start 276.427184 -311.073038)
		(end 274.012914 -311.073038)
		(width 0.18288)
		(layer "In6.Cu")
		(net "M_D_CPU0_SA_DQS_DP<5>")
	)
	(segment
		(start 342.116664 -274.591272)
		(end 342.101932 -274.582636)
		(width 0.088646)
		(layer "In6.Cu")
		(net "M_D_CPU0_SA_DQS_DP<5>")
	)
	(segment
		(start 284.132782 -312.491628)
		(end 283.694124 -312.491628)
		(width 0.18288)
		(layer "In6.Cu")
		(net "M_D_CPU0_SA_DQS_DP<5>")
	)
	(segment
		(start 343.99855 -274.592542)
		(end 343.99728 -274.59178)
		(width 0.088646)
		(layer "In6.Cu")
		(net "M_D_CPU0_SA_DQS_DP<5>")
	)
	(segment
		(start 291.379656 -309.60822)
		(end 290.93668 -309.60822)
		(width 0.18288)
		(layer "In6.Cu")
		(net "M_D_CPU0_SA_DQS_DP<5>")
	)
	(segment
		(start 331.460094 -279.796748)
		(end 331.436726 -279.796748)
		(width 0.088646)
		(layer "In6.Cu")
		(net "M_D_CPU0_SA_DQS_DP<5>")
	)
	(segment
		(start 298.781724 -304.841656)
		(end 298.532296 -305.091084)
		(width 0.18288)
		(layer "In6.Cu")
		(net "M_D_CPU0_SA_DQS_DP<5>")
	)
	(segment
		(start 320.990976 -288.996882)
		(end 320.602864 -289.384994)
		(width 0.18288)
		(layer "In6.Cu")
		(net "M_D_CPU0_SA_DQS_DP<5>")
	)
	(segment
		(start 295.442894 -307.652166)
		(end 295.182544 -307.391816)
		(width 0.18288)
		(layer "In6.Cu")
		(net "M_D_CPU0_SA_DQS_DP<5>")
	)
	(segment
		(start 309.533036 -297.73372)
		(end 308.141116 -299.12564)
		(width 0.18288)
		(layer "In6.Cu")
		(net "M_D_CPU0_SA_DQS_DP<5>")
	)
	(segment
		(start 315.997844 -294.16629)
		(end 315.997844 -294.76827)
		(width 0.18288)
		(layer "In6.Cu")
		(net "M_D_CPU0_SA_DQS_DP<5>")
	)
	(segment
		(start 298.532296 -305.091084)
		(end 298.007278 -305.091084)
		(width 0.18288)
		(layer "In6.Cu")
		(net "M_D_CPU0_SA_DQS_DP<5>")
	)
	(segment
		(start 339.682328 -274.585176)
		(end 339.671914 -274.591272)
		(width 0.088646)
		(layer "In6.Cu")
		(net "M_D_CPU0_SA_DQS_DP<5>")
	)
	(segment
		(start 295.90492 -306.728368)
		(end 295.905682 -307.322982)
		(width 0.18288)
		(layer "In6.Cu")
		(net "M_D_CPU0_SA_DQS_DP<5>")
	)
	(segment
		(start 306.517802 -299.956982)
		(end 305.711098 -300.763686)
		(width 0.18288)
		(layer "In6.Cu")
		(net "M_D_CPU0_SA_DQS_DP<5>")
	)
	(segment
		(start 311.444894 -298.138088)
		(end 311.040526 -297.73372)
		(width 0.18288)
		(layer "In6.Cu")
		(net "M_D_CPU0_SA_DQS_DP<5>")
	)
	(segment
		(start 321.166998 -288.996882)
		(end 320.990976 -288.996882)
		(width 0.18288)
		(layer "In6.Cu")
		(net "M_D_CPU0_SA_DQS_DP<5>")
	)
	(segment
		(start 296.793666 -305.839622)
		(end 295.90492 -306.728368)
		(width 0.18288)
		(layer "In6.Cu")
		(net "M_D_CPU0_SA_DQS_DP<5>")
	)
	(segment
		(start 305.711098 -300.763686)
		(end 305.711098 -301.281592)
		(width 0.18288)
		(layer "In6.Cu")
		(net "M_D_CPU0_SA_DQS_DP<5>")
	)
	(segment
		(start 320.602864 -289.561016)
		(end 320.215006 -289.948874)
		(width 0.18288)
		(layer "In6.Cu")
		(net "M_D_CPU0_SA_DQS_DP<5>")
	)
	(segment
		(start 325.926958 -284.236922)
		(end 325.750936 -284.236922)
		(width 0.18288)
		(layer "In6.Cu")
		(net "M_D_CPU0_SA_DQS_DP<5>")
	)
	(segment
		(start 269.08887 -311.47639)
		(end 268.829282 -311.216802)
		(width 0.18288)
		(layer "In6.Cu")
		(net "M_D_CPU0_SA_DQS_DP<5>")
	)
	(segment
		(start 305.711098 -301.281592)
		(end 304.707544 -302.285146)
		(width 0.18288)
		(layer "In6.Cu")
		(net "M_D_CPU0_SA_DQS_DP<5>")
	)
	(segment
		(start 269.854934 -311.737756)
		(end 269.593568 -311.47639)
		(width 0.18288)
		(layer "In6.Cu")
		(net "M_D_CPU0_SA_DQS_DP<5>")
	)
	(segment
		(start 343.99728 -274.59178)
		(end 343.996264 -274.591272)
		(width 0.088646)
		(layer "In6.Cu")
		(net "M_D_CPU0_SA_DQS_DP<5>")
	)
	(segment
		(start 318.69888 -291.465)
		(end 315.997844 -294.16629)
		(width 0.18288)
		(layer "In6.Cu")
		(net "M_D_CPU0_SA_DQS_DP<5>")
	)
	(segment
		(start 329.558904 -280.428954)
		(end 329.170792 -280.817066)
		(width 0.18288)
		(layer "In6.Cu")
		(net "M_D_CPU0_SA_DQS_DP<5>")
	)
	(segment
		(start 325.362824 -284.801056)
		(end 324.974966 -285.188914)
		(width 0.18288)
		(layer "In6.Cu")
		(net "M_D_CPU0_SA_DQS_DP<5>")
	)
	(segment
		(start 278.721312 -311.073292)
		(end 278.10333 -310.45531)
		(width 0.18288)
		(layer "In6.Cu")
		(net "M_D_CPU0_SA_DQS_DP<5>")
	)
	(segment
		(start 295.905682 -307.322982)
		(end 295.576498 -307.652166)
		(width 0.18288)
		(layer "In6.Cu")
		(net "M_D_CPU0_SA_DQS_DP<5>")
	)
	(segment
		(start 321.942968 -288.04489)
		(end 321.554856 -288.433002)
		(width 0.18288)
		(layer "In6.Cu")
		(net "M_D_CPU0_SA_DQS_DP<5>")
	)
	(segment
		(start 334.51165 -277.027894)
		(end 334.50276 -277.032974)
		(width 0.088646)
		(layer "In6.Cu")
		(net "M_D_CPU0_SA_DQS_DP<5>")
	)
	(segment
		(start 274.012914 -311.073038)
		(end 272.408142 -311.737756)
		(width 0.18288)
		(layer "In6.Cu")
		(net "M_D_CPU0_SA_DQS_DP<5>")
	)
	(segment
		(start 326.87895 -283.28493)
		(end 326.702928 -283.28493)
		(width 0.18288)
		(layer "In6.Cu")
		(net "M_D_CPU0_SA_DQS_DP<5>")
	)
	(segment
		(start 331.436726 -279.796748)
		(end 330.71308 -279.796748)
		(width 0.18288)
		(layer "In6.Cu")
		(net "M_D_CPU0_SA_DQS_DP<5>")
	)
	(segment
		(start 328.2188 -281.769058)
		(end 328.2188 -281.94508)
		(width 0.18288)
		(layer "In6.Cu")
		(net "M_D_CPU0_SA_DQS_DP<5>")
	)
	(segment
		(start 324.410832 -285.753048)
		(end 324.022974 -286.140906)
		(width 0.18288)
		(layer "In6.Cu")
		(net "M_D_CPU0_SA_DQS_DP<5>")
	)
	(segment
		(start 325.362824 -284.625034)
		(end 325.362824 -284.801056)
		(width 0.18288)
		(layer "In6.Cu")
		(net "M_D_CPU0_SA_DQS_DP<5>")
	)
	(segment
		(start 306.778914 -299.956982)
		(end 306.517802 -299.956982)
		(width 0.18288)
		(layer "In6.Cu")
		(net "M_D_CPU0_SA_DQS_DP<5>")
	)
	(segment
		(start 283.444696 -312.741056)
		(end 283.167582 -312.741056)
		(width 0.18288)
		(layer "In6.Cu")
		(net "M_D_CPU0_SA_DQS_DP<5>")
	)
	(segment
		(start 279.331674 -311.073292)
		(end 278.721312 -311.073292)
		(width 0.18288)
		(layer "In6.Cu")
		(net "M_D_CPU0_SA_DQS_DP<5>")
	)
	(segment
		(start 297.25874 -305.839622)
		(end 296.793666 -305.839622)
		(width 0.18288)
		(layer "In6.Cu")
		(net "M_D_CPU0_SA_DQS_DP<5>")
	)
	(segment
		(start 282.073858 -311.647332)
		(end 280.636726 -311.05221)
		(width 0.18288)
		(layer "In6.Cu")
		(net "M_D_CPU0_SA_DQS_DP<5>")
	)
	(segment
		(start 289.683698 -310.860948)
		(end 285.119572 -312.752232)
		(width 0.18288)
		(layer "In6.Cu")
		(net "M_D_CPU0_SA_DQS_DP<5>")
	)
	(segment
		(start 323.45884 -286.70504)
		(end 323.070982 -287.092898)
		(width 0.18288)
		(layer "In6.Cu")
		(net "M_D_CPU0_SA_DQS_DP<5>")
	)
	(segment
		(start 323.45884 -286.529018)
		(end 323.45884 -286.70504)
		(width 0.18288)
		(layer "In6.Cu")
		(net "M_D_CPU0_SA_DQS_DP<5>")
	)
	(segment
		(start 336.477864 -276.219158)
		(end 336.46745 -276.213062)
		(width 0.088646)
		(layer "In6.Cu")
		(net "M_D_CPU0_SA_DQS_DP<5>")
	)
	(segment
		(start 283.167582 -312.741056)
		(end 282.073858 -311.647332)
		(width 0.18288)
		(layer "In6.Cu")
		(net "M_D_CPU0_SA_DQS_DP<5>")
	)
	(segment
		(start 290.93668 -309.60822)
		(end 289.683698 -310.860948)
		(width 0.18288)
		(layer "In6.Cu")
		(net "M_D_CPU0_SA_DQS_DP<5>")
	)
	(segment
		(start 325.750936 -284.236922)
		(end 325.362824 -284.625034)
		(width 0.18288)
		(layer "In6.Cu")
		(net "M_D_CPU0_SA_DQS_DP<5>")
	)
	(segment
		(start 331.803248 -279.856692)
		(end 331.520038 -279.856692)
		(width 0.088646)
		(layer "In6.Cu")
		(net "M_D_CPU0_SA_DQS_DP<5>")
	)
	(segment
		(start 278.10333 -310.45531)
		(end 277.044912 -310.45531)
		(width 0.18288)
		(layer "In6.Cu")
		(net "M_D_CPU0_SA_DQS_DP<5>")
	)
	(segment
		(start 321.554856 -288.433002)
		(end 321.554856 -288.609024)
		(width 0.18288)
		(layer "In6.Cu")
		(net "M_D_CPU0_SA_DQS_DP<5>")
	)
	(segment
		(start 335.53781 -276.219158)
		(end 335.523078 -276.210522)
		(width 0.088646)
		(layer "In6.Cu")
		(net "M_D_CPU0_SA_DQS_DP<5>")
	)
	(segment
		(start 319.650872 -290.513008)
		(end 319.263014 -290.900866)
		(width 0.18288)
		(layer "In6.Cu")
		(net "M_D_CPU0_SA_DQS_DP<5>")
	)
	(segment
		(start 285.119572 -312.752232)
		(end 284.393386 -312.752232)
		(width 0.18288)
		(layer "In6.Cu")
		(net "M_D_CPU0_SA_DQS_DP<5>")
	)
	(segment
		(start 328.2188 -281.94508)
		(end 327.830942 -282.332938)
		(width 0.18288)
		(layer "In6.Cu")
		(net "M_D_CPU0_SA_DQS_DP<5>")
	)
	(segment
		(start 279.347168 -311.062878)
		(end 279.342088 -311.062878)
		(width 0.18288)
		(layer "In6.Cu")
		(net "M_D_CPU0_SA_DQS_DP<5>")
	)
	(segment
		(start 322.89496 -287.092898)
		(end 322.506848 -287.48101)
		(width 0.18288)
		(layer "In6.Cu")
		(net "M_D_CPU0_SA_DQS_DP<5>")
	)
	(segment
		(start 344.653616 -275.08073)
		(end 344.653108 -275.08073)
		(width 0.088646)
		(layer "In6.Cu")
		(net "M_D_CPU0_SA_DQS_DP<5>")
	)
	(segment
		(start 333.147416 -277.421086)
		(end 333.147416 -277.833074)
		(width 0.088646)
		(layer "In6.Cu")
		(net "M_D_CPU0_SA_DQS_DP<5>")
	)
	(segment
		(start 324.974966 -285.188914)
		(end 324.798944 -285.188914)
		(width 0.18288)
		(layer "In6.Cu")
		(net "M_D_CPU0_SA_DQS_DP<5>")
	)
	(segment
		(start 341.176864 -274.591272)
		(end 341.162132 -274.582636)
		(width 0.088646)
		(layer "In6.Cu")
		(net "M_D_CPU0_SA_DQS_DP<5>")
	)
	(segment
		(start 343.996264 -274.591272)
		(end 343.981532 -274.582636)
		(width 0.088646)
		(layer "In6.Cu")
		(net "M_D_CPU0_SA_DQS_DP<5>")
	)
	(segment
		(start 329.170792 -280.993088)
		(end 328.782934 -281.380946)
		(width 0.18288)
		(layer "In6.Cu")
		(net "M_D_CPU0_SA_DQS_DP<5>")
	)
	(segment
		(start 294.681402 -307.391816)
		(end 294.421814 -307.651404)
		(width 0.18288)
		(layer "In6.Cu")
		(net "M_D_CPU0_SA_DQS_DP<5>")
	)
	(segment
		(start 344.373962 -274.809966)
		(end 344.000836 -274.594066)
		(width 0.088646)
		(layer "In6.Cu")
		(net "M_D_CPU0_SA_DQS_DP<5>")
	)
	(segment
		(start 277.044912 -310.45531)
		(end 276.427184 -311.073038)
		(width 0.18288)
		(layer "In6.Cu")
		(net "M_D_CPU0_SA_DQS_DP<5>")
	)
	(segment
		(start 337.33105 -275.400008)
		(end 337.322922 -275.40458)
		(width 0.088646)
		(layer "In6.Cu")
		(net "M_D_CPU0_SA_DQS_DP<5>")
	)
	(segment
		(start 330.71308 -279.796748)
		(end 330.122784 -280.041096)
		(width 0.18288)
		(layer "In6.Cu")
		(net "M_D_CPU0_SA_DQS_DP<5>")
	)
	(segment
		(start 326.314816 -283.673042)
		(end 326.314816 -283.849064)
		(width 0.18288)
		(layer "In6.Cu")
		(net "M_D_CPU0_SA_DQS_DP<5>")
	)
	(segment
		(start 320.038984 -289.948874)
		(end 319.650872 -290.336986)
		(width 0.18288)
		(layer "In6.Cu")
		(net "M_D_CPU0_SA_DQS_DP<5>")
	)
	(segment
		(start 295.182544 -307.391816)
		(end 294.681402 -307.391816)
		(width 0.18288)
		(layer "In6.Cu")
		(net "M_D_CPU0_SA_DQS_DP<5>")
	)
	(segment
		(start 308.141116 -299.12564)
		(end 307.610256 -299.12564)
		(width 0.18288)
		(layer "In6.Cu")
		(net "M_D_CPU0_SA_DQS_DP<5>")
	)
	(segment
		(start 279.342088 -311.062878)
		(end 279.331674 -311.073292)
		(width 0.18288)
		(layer "In6.Cu")
		(net "M_D_CPU0_SA_DQS_DP<5>")
	)
	(segment
		(start 344.000836 -274.594066)
		(end 343.99855 -274.592542)
		(width 0.088646)
		(layer "In6.Cu")
		(net "M_D_CPU0_SA_DQS_DP<5>")
	)
	(segment
		(start 284.393386 -312.752232)
		(end 284.132782 -312.491628)
		(width 0.18288)
		(layer "In6.Cu")
		(net "M_D_CPU0_SA_DQS_DP<5>")
	)
	(segment
		(start 300.410372 -305.10226)
		(end 299.542962 -305.10226)
		(width 0.18288)
		(layer "In6.Cu")
		(net "M_D_CPU0_SA_DQS_DP<5>")
	)
	(segment
		(start 279.618186 -310.79186)
		(end 279.347168 -311.062878)
		(width 0.18288)
		(layer "In6.Cu")
		(net "M_D_CPU0_SA_DQS_DP<5>")
	)
	(segment
		(start 327.830942 -282.332938)
		(end 327.65492 -282.332938)
		(width 0.18288)
		(layer "In6.Cu")
		(net "M_D_CPU0_SA_DQS_DP<5>")
	)
	(segment
		(start 299.542962 -305.10226)
		(end 299.282358 -304.841656)
		(width 0.18288)
		(layer "In6.Cu")
		(net "M_D_CPU0_SA_DQS_DP<5>")
	)
	(segment
		(start 327.65492 -282.332938)
		(end 327.266808 -282.72105)
		(width 0.18288)
		(layer "In6.Cu")
		(net "M_D_CPU0_SA_DQS_DP<5>")
	)
	(segment
		(start 327.266808 -282.897072)
		(end 326.87895 -283.28493)
		(width 0.18288)
		(layer "In6.Cu")
		(net "M_D_CPU0_SA_DQS_DP<5>")
	)
	(segment
		(start 331.520038 -279.856692)
		(end 331.460094 -279.796748)
		(width 0.088646)
		(layer "In6.Cu")
		(net "M_D_CPU0_SA_DQS_DP<5>")
	)
	(segment
		(start 333.147416 -277.833074)
		(end 332.039722 -278.940768)
		(width 0.088646)
		(layer "In6.Cu")
		(net "M_D_CPU0_SA_DQS_DP<5>")
	)
	(segment
		(start 324.022974 -286.140906)
		(end 323.846952 -286.140906)
		(width 0.18288)
		(layer "In6.Cu")
		(net "M_D_CPU0_SA_DQS_DP<5>")
	)
	(segment
		(start 320.602864 -289.384994)
		(end 320.602864 -289.561016)
		(width 0.18288)
		(layer "In6.Cu")
		(net "M_D_CPU0_SA_DQS_DP<5>")
	)
	(segment
		(start 324.410832 -285.577026)
		(end 324.410832 -285.753048)
		(width 0.18288)
		(layer "In6.Cu")
		(net "M_D_CPU0_SA_DQS_DP<5>")
	)
	(segment
		(start 324.798944 -285.188914)
		(end 324.410832 -285.577026)
		(width 0.18288)
		(layer "In6.Cu")
		(net "M_D_CPU0_SA_DQS_DP<5>")
	)
	(segment
		(start 320.215006 -289.948874)
		(end 320.038984 -289.948874)
		(width 0.18288)
		(layer "In6.Cu")
		(net "M_D_CPU0_SA_DQS_DP<5>")
	)
	(segment
		(start 334.690212 -276.693122)
		(end 334.690212 -276.708616)
		(width 0.088646)
		(layer "In6.Cu")
		(net "M_D_CPU0_SA_DQS_DP<5>")
	)
	(segment
		(start 322.506848 -287.48101)
		(end 322.506848 -287.657032)
		(width 0.18288)
		(layer "In6.Cu")
		(net "M_D_CPU0_SA_DQS_DP<5>")
	)
	(segment
		(start 323.070982 -287.092898)
		(end 322.89496 -287.092898)
		(width 0.18288)
		(layer "In6.Cu")
		(net "M_D_CPU0_SA_DQS_DP<5>")
	)
	(segment
		(start 339.297518 -274.591272)
		(end 339.287104 -274.585176)
		(width 0.088646)
		(layer "In6.Cu")
		(net "M_D_CPU0_SA_DQS_DP<5>")
	)
	(segment
		(start 319.263014 -290.900866)
		(end 319.086992 -290.900866)
		(width 0.18288)
		(layer "In6.Cu")
		(net "M_D_CPU0_SA_DQS_DP<5>")
	)
	(segment
		(start 337.039712 -275.876258)
		(end 337.039712 -275.8948)
		(width 0.088646)
		(layer "In6.Cu")
		(net "M_D_CPU0_SA_DQS_DP<5>")
	)
	(segment
		(start 321.554856 -288.609024)
		(end 321.166998 -288.996882)
		(width 0.18288)
		(layer "In6.Cu")
		(net "M_D_CPU0_SA_DQS_DP<5>")
	)
	(segment
		(start 326.314816 -283.849064)
		(end 325.926958 -284.236922)
		(width 0.18288)
		(layer "In6.Cu")
		(net "M_D_CPU0_SA_DQS_DP<5>")
	)
	(segment
		(start 322.506848 -287.657032)
		(end 322.11899 -288.04489)
		(width 0.18288)
		(layer "In6.Cu")
		(net "M_D_CPU0_SA_DQS_DP<5>")
	)
	(segment
		(start 298.007278 -305.091084)
		(end 297.25874 -305.839622)
		(width 0.18288)
		(layer "In6.Cu")
		(net "M_D_CPU0_SA_DQS_DP<5>")
	)
	(segment
		(start 330.122784 -280.041096)
		(end 329.734926 -280.428954)
		(width 0.18288)
		(layer "In6.Cu")
		(net "M_D_CPU0_SA_DQS_DP<5>")
	)
	(segment
		(start 311.040526 -297.73372)
		(end 309.533036 -297.73372)
		(width 0.18288)
		(layer "In6.Cu")
		(net "M_D_CPU0_SA_DQS_DP<5>")
	)
	(segment
		(start 328.782934 -281.380946)
		(end 328.606912 -281.380946)
		(width 0.18288)
		(layer "In6.Cu")
		(net "M_D_CPU0_SA_DQS_DP<5>")
	)
	(segment
		(start 333.445866 -277.122382)
		(end 333.147416 -277.421086)
		(width 0.088646)
		(layer "In6.Cu")
		(net "M_D_CPU0_SA_DQS_DP<5>")
	)
	(segment
		(start 326.702928 -283.28493)
		(end 326.314816 -283.673042)
		(width 0.18288)
		(layer "In6.Cu")
		(net "M_D_CPU0_SA_DQS_DP<5>")
	)
	(segment
		(start 322.11899 -288.04489)
		(end 321.942968 -288.04489)
		(width 0.18288)
		(layer "In6.Cu")
		(net "M_D_CPU0_SA_DQS_DP<5>")
	)
	(segment
		(start 328.606912 -281.380946)
		(end 328.2188 -281.769058)
		(width 0.18288)
		(layer "In6.Cu")
		(net "M_D_CPU0_SA_DQS_DP<5>")
	)
	(segment
		(start 343.056464 -274.591272)
		(end 343.041732 -274.582636)
		(width 0.088646)
		(layer "In6.Cu")
		(net "M_D_CPU0_SA_DQS_DP<5>")
	)
	(segment
		(start 329.170792 -280.817066)
		(end 329.170792 -280.993088)
		(width 0.18288)
		(layer "In6.Cu")
		(net "M_D_CPU0_SA_DQS_DP<5>")
	)
	(segment
		(start 303.038002 -303.568862)
		(end 301.94377 -303.568862)
		(width 0.18288)
		(layer "In6.Cu")
		(net "M_D_CPU0_SA_DQS_DP<5>")
	)
	(segment
		(start 337.322922 -275.40458)
		(end 337.32216 -275.405088)
		(width 0.088646)
		(layer "In6.Cu")
		(net "M_D_CPU0_SA_DQS_DP<5>")
	)
	(segment
		(start 280.636726 -311.05221)
		(end 280.283158 -311.05221)
		(width 0.18288)
		(layer "In6.Cu")
		(net "M_D_CPU0_SA_DQS_DP<5>")
	)
	(segment
		(start 332.039722 -279.620218)
		(end 331.803248 -279.856692)
		(width 0.088646)
		(layer "In6.Cu")
		(net "M_D_CPU0_SA_DQS_DP<5>")
	)
	(segment
		(start 337.509612 -275.070824)
		(end 337.509612 -275.08073)
		(width 0.088646)
		(layer "In6.Cu")
		(net "M_D_CPU0_SA_DQS_DP<5>")
	)
	(segment
		(start 332.039722 -278.940768)
		(end 332.039722 -279.620218)
		(width 0.088646)
		(layer "In6.Cu")
		(net "M_D_CPU0_SA_DQS_DP<5>")
	)
	(segment
		(start 323.846952 -286.140906)
		(end 323.45884 -286.529018)
		(width 0.18288)
		(layer "In6.Cu")
		(net "M_D_CPU0_SA_DQS_DP<5>")
	)
	(segment
		(start 301.94377 -303.568862)
		(end 300.410372 -305.10226)
		(width 0.18288)
		(layer "In6.Cu")
		(net "M_D_CPU0_SA_DQS_DP<5>")
	)
	(segment
		(start 293.220902 -308.278276)
		(end 292.7096 -308.278276)
		(width 0.18288)
		(layer "In6.Cu")
		(net "M_D_CPU0_SA_DQS_DP<5>")
	)
	(segment
		(start 295.576498 -307.652166)
		(end 295.442894 -307.652166)
		(width 0.18288)
		(layer "In6.Cu")
		(net "M_D_CPU0_SA_DQS_DP<5>")
	)
	(segment
		(start 314.056522 -296.709592)
		(end 313.727084 -296.709592)
		(width 0.18288)
		(layer "In6.Cu")
		(net "M_D_CPU0_SA_DQS_DP<5>")
	)
	(segment
		(start 294.421814 -307.651404)
		(end 293.847774 -307.651404)
		(width 0.18288)
		(layer "In6.Cu")
		(net "M_D_CPU0_SA_DQS_DP<5>")
	)
	(segment
		(start 280.283158 -311.05221)
		(end 280.022808 -310.79186)
		(width 0.18288)
		(layer "In6.Cu")
		(net "M_D_CPU0_SA_DQS_DP<5>")
	)
	(segment
		(start 312.298588 -298.138088)
		(end 311.444894 -298.138088)
		(width 0.18288)
		(layer "In6.Cu")
		(net "M_D_CPU0_SA_DQS_DP<5>")
	)
	(arc
		(start 335.523078 -276.210522)
		(mid 335.246603 -276.143202)
		(end 334.972406 -276.219158)
		(width 0.088646)
		(layer "In6.Cu")
		(net "M_D_CPU0_SA_DQS_DP<5>")
	)
	(arc
		(start 342.101932 -274.582636)
		(mid 341.825457 -274.515316)
		(end 341.55126 -274.591272)
		(width 0.088646)
		(layer "In6.Cu")
		(net "M_D_CPU0_SA_DQS_DP<5>")
	)
	(arc
		(start 334.972406 -276.219158)
		(mid 334.769583 -276.419389)
		(end 334.690212 -276.693122)
		(width 0.088646)
		(layer "In6.Cu")
		(net "M_D_CPU0_SA_DQS_DP<5>")
	)
	(arc
		(start 343.041732 -274.582636)
		(mid 342.765257 -274.515316)
		(end 342.49106 -274.591272)
		(width 0.088646)
		(layer "In6.Cu")
		(net "M_D_CPU0_SA_DQS_DP<5>")
	)
	(arc
		(start 338.357464 -274.591272)
		(mid 338.074762 -274.515496)
		(end 337.79206 -274.591272)
		(width 0.088646)
		(layer "In6.Cu")
		(net "M_D_CPU0_SA_DQS_DP<5>")
	)
	(arc
		(start 340.237064 -274.591272)
		(mid 339.960505 -274.515529)
		(end 339.682328 -274.585176)
		(width 0.088646)
		(layer "In6.Cu")
		(net "M_D_CPU0_SA_DQS_DP<5>")
	)
	(arc
		(start 334.50276 -277.032974)
		(mid 334.315562 -277.083117)
		(end 334.128364 -277.032974)
		(width 0.088646)
		(layer "In6.Cu")
		(net "M_D_CPU0_SA_DQS_DP<5>")
	)
	(arc
		(start 339.287104 -274.585176)
		(mid 339.008672 -274.51533)
		(end 338.73186 -274.591272)
		(width 0.088646)
		(layer "In6.Cu")
		(net "M_D_CPU0_SA_DQS_DP<5>")
	)
	(arc
		(start 341.55126 -274.591272)
		(mid 341.364062 -274.641415)
		(end 341.176864 -274.591272)
		(width 0.088646)
		(layer "In6.Cu")
		(net "M_D_CPU0_SA_DQS_DP<5>")
	)
	(arc
		(start 336.46745 -276.213062)
		(mid 336.189018 -276.143216)
		(end 335.912206 -276.219158)
		(width 0.088646)
		(layer "In6.Cu")
		(net "M_D_CPU0_SA_DQS_DP<5>")
	)
	(arc
		(start 340.61146 -274.591272)
		(mid 340.424262 -274.641415)
		(end 340.237064 -274.591272)
		(width 0.088646)
		(layer "In6.Cu")
		(net "M_D_CPU0_SA_DQS_DP<5>")
	)
	(arc
		(start 341.162132 -274.582636)
		(mid 340.885657 -274.515316)
		(end 340.61146 -274.591272)
		(width 0.088646)
		(layer "In6.Cu")
		(net "M_D_CPU0_SA_DQS_DP<5>")
	)
	(arc
		(start 337.79206 -274.591272)
		(mid 337.587725 -274.793877)
		(end 337.509612 -275.070824)
		(width 0.088646)
		(layer "In6.Cu")
		(net "M_D_CPU0_SA_DQS_DP<5>")
	)
	(arc
		(start 339.671914 -274.591272)
		(mid 339.484716 -274.641415)
		(end 339.297518 -274.591272)
		(width 0.088646)
		(layer "In6.Cu")
		(net "M_D_CPU0_SA_DQS_DP<5>")
	)
	(arc
		(start 336.85226 -276.219158)
		(mid 336.665062 -276.269301)
		(end 336.477864 -276.219158)
		(width 0.088646)
		(layer "In6.Cu")
		(net "M_D_CPU0_SA_DQS_DP<5>")
	)
	(arc
		(start 342.49106 -274.591272)
		(mid 342.303862 -274.641415)
		(end 342.116664 -274.591272)
		(width 0.088646)
		(layer "In6.Cu")
		(net "M_D_CPU0_SA_DQS_DP<5>")
	)
	(arc
		(start 334.690212 -276.708616)
		(mid 334.642533 -276.891516)
		(end 334.51165 -277.027894)
		(width 0.088646)
		(layer "In6.Cu")
		(net "M_D_CPU0_SA_DQS_DP<5>")
	)
	(arc
		(start 337.32216 -275.405088)
		(mid 337.119874 -275.604069)
		(end 337.039712 -275.876258)
		(width 0.088646)
		(layer "In6.Cu")
		(net "M_D_CPU0_SA_DQS_DP<5>")
	)
	(arc
		(start 333.469996 -277.099776)
		(mid 333.457764 -277.110901)
		(end 333.445866 -277.122382)
		(width 0.088646)
		(layer "In6.Cu")
		(net "M_D_CPU0_SA_DQS_DP<5>")
	)
	(arc
		(start 338.73186 -274.591272)
		(mid 338.544662 -274.641415)
		(end 338.357464 -274.591272)
		(width 0.088646)
		(layer "In6.Cu")
		(net "M_D_CPU0_SA_DQS_DP<5>")
	)
	(arc
		(start 337.509612 -275.08073)
		(mid 337.461933 -275.26363)
		(end 337.33105 -275.400008)
		(width 0.088646)
		(layer "In6.Cu")
		(net "M_D_CPU0_SA_DQS_DP<5>")
	)
	(arc
		(start 343.43086 -274.591272)
		(mid 343.243662 -274.641415)
		(end 343.056464 -274.591272)
		(width 0.088646)
		(layer "In6.Cu")
		(net "M_D_CPU0_SA_DQS_DP<5>")
	)
	(arc
		(start 343.981532 -274.582636)
		(mid 343.705057 -274.515316)
		(end 343.43086 -274.591272)
		(width 0.088646)
		(layer "In6.Cu")
		(net "M_D_CPU0_SA_DQS_DP<5>")
	)
	(arc
		(start 337.039712 -275.8948)
		(mid 336.992033 -276.0777)
		(end 336.86115 -276.214078)
		(width 0.088646)
		(layer "In6.Cu")
		(net "M_D_CPU0_SA_DQS_DP<5>")
	)
	(arc
		(start 335.912206 -276.219158)
		(mid 335.725008 -276.269301)
		(end 335.53781 -276.219158)
		(width 0.088646)
		(layer "In6.Cu")
		(net "M_D_CPU0_SA_DQS_DP<5>")
	)
	(arc
		(start 334.128364 -277.032974)
		(mid 333.788372 -276.959988)
		(end 333.469996 -277.099776)
		(width 0.088646)
		(layer "In6.Cu")
		(net "M_D_CPU0_SA_DQS_DP<5>")
	)
	(segment
		(start 259.302758 -275.94179)
		(end 259.065776 -275.94179)
		(width 0.101854)
		(layer "F.Cu")
		(net "M_D_CPU0_SA_DQS_DP<4>")
	)
	(segment
		(start 257.30454 -275.255482)
		(end 256.879598 -275.255482)
		(width 0.20066)
		(layer "F.Cu")
		(net "M_D_CPU0_SA_DQS_DP<4>")
	)
	(segment
		(start 263.624314 -275.516594)
		(end 263.075674 -275.516594)
		(width 0.20066)
		(layer "F.Cu")
		(net "M_D_CPU0_SA_DQS_DP<4>")
	)
	(segment
		(start 258.567682 -275.680678)
		(end 257.940556 -275.680678)
		(width 0.20066)
		(layer "F.Cu")
		(net "M_D_CPU0_SA_DQS_DP<4>")
	)
	(segment
		(start 347.003116 -262.87222)
		(end 347.002862 -262.872474)
		(width 0.20066)
		(layer "F.Cu")
		(net "M_D_CPU0_SA_DQS_DP<4>")
	)
	(segment
		(start 259.056378 -275.951188)
		(end 258.838192 -275.951188)
		(width 0.20066)
		(layer "F.Cu")
		(net "M_D_CPU0_SA_DQS_DP<4>")
	)
	(segment
		(start 347.003116 -262.336534)
		(end 347.003116 -262.87222)
		(width 0.20066)
		(layer "F.Cu")
		(net "M_D_CPU0_SA_DQS_DP<4>")
	)
	(segment
		(start 256.879598 -275.255482)
		(end 256.618486 -275.516594)
		(width 0.20066)
		(layer "F.Cu")
		(net "M_D_CPU0_SA_DQS_DP<4>")
	)
	(segment
		(start 257.940556 -275.680678)
		(end 257.30454 -275.255482)
		(width 0.20066)
		(layer "F.Cu")
		(net "M_D_CPU0_SA_DQS_DP<4>")
	)
	(segment
		(start 261.794752 -275.680678)
		(end 261.53364 -275.94179)
		(width 0.20066)
		(layer "F.Cu")
		(net "M_D_CPU0_SA_DQS_DP<4>")
	)
	(segment
		(start 263.075674 -275.516594)
		(end 262.814562 -275.255482)
		(width 0.20066)
		(layer "F.Cu")
		(net "M_D_CPU0_SA_DQS_DP<4>")
	)
	(segment
		(start 261.058152 -275.94179)
		(end 259.302758 -275.94179)
		(width 0.1016)
		(layer "F.Cu")
		(net "M_D_CPU0_SA_DQS_DP<4>")
	)
	(segment
		(start 261.381494 -275.94179)
		(end 261.058152 -275.94179)
		(width 0.101854)
		(layer "F.Cu")
		(net "M_D_CPU0_SA_DQS_DP<4>")
	)
	(segment
		(start 262.54583 -275.255482)
		(end 262.120634 -275.680678)
		(width 0.20066)
		(layer "F.Cu")
		(net "M_D_CPU0_SA_DQS_DP<4>")
	)
	(segment
		(start 256.618486 -275.516594)
		(end 256.080514 -275.516594)
		(width 0.20066)
		(layer "F.Cu")
		(net "M_D_CPU0_SA_DQS_DP<4>")
	)
	(segment
		(start 259.065776 -275.94179)
		(end 259.056378 -275.951188)
		(width 0.101854)
		(layer "F.Cu")
		(net "M_D_CPU0_SA_DQS_DP<4>")
	)
	(segment
		(start 264.729214 -275.516594)
		(end 263.624314 -275.516594)
		(width 0.20066)
		(layer "F.Cu")
		(net "M_D_CPU0_SA_DQS_DP<4>")
	)
	(segment
		(start 262.120634 -275.680678)
		(end 261.794752 -275.680678)
		(width 0.20066)
		(layer "F.Cu")
		(net "M_D_CPU0_SA_DQS_DP<4>")
	)
	(segment
		(start 258.838192 -275.951188)
		(end 258.567682 -275.680678)
		(width 0.20066)
		(layer "F.Cu")
		(net "M_D_CPU0_SA_DQS_DP<4>")
	)
	(segment
		(start 262.814562 -275.255482)
		(end 262.54583 -275.255482)
		(width 0.20066)
		(layer "F.Cu")
		(net "M_D_CPU0_SA_DQS_DP<4>")
	)
	(segment
		(start 261.53364 -275.94179)
		(end 261.381494 -275.94179)
		(width 0.20066)
		(layer "F.Cu")
		(net "M_D_CPU0_SA_DQS_DP<4>")
	)
	(segment
		(start 277.316184 -274.657566)
		(end 276.824694 -274.166076)
		(width 0.18288)
		(layer "In11.Cu")
		(net "M_D_CPU0_SA_DQS_DP<4>")
	)
	(segment
		(start 331.037184 -263.83361)
		(end 330.97724 -263.893554)
		(width 0.088646)
		(layer "In11.Cu")
		(net "M_D_CPU0_SA_DQS_DP<4>")
	)
	(segment
		(start 294.45077 -273.979132)
		(end 293.818056 -273.979132)
		(width 0.18288)
		(layer "In11.Cu")
		(net "M_D_CPU0_SA_DQS_DP<4>")
	)
	(segment
		(start 278.237188 -274.657566)
		(end 277.316184 -274.657566)
		(width 0.18288)
		(layer "In11.Cu")
		(net "M_D_CPU0_SA_DQS_DP<4>")
	)
	(segment
		(start 298.550076 -273.128486)
		(end 297.825922 -273.128486)
		(width 0.18288)
		(layer "In11.Cu")
		(net "M_D_CPU0_SA_DQS_DP<4>")
	)
	(segment
		(start 269.008606 -275.942806)
		(end 268.650212 -275.942806)
		(width 0.18288)
		(layer "In11.Cu")
		(net "M_D_CPU0_SA_DQS_DP<4>")
	)
	(segment
		(start 291.56025 -273.866864)
		(end 288.057082 -273.866864)
		(width 0.18288)
		(layer "In11.Cu")
		(net "M_D_CPU0_SA_DQS_DP<4>")
	)
	(segment
		(start 292.350952 -274.657566)
		(end 291.56025 -273.866864)
		(width 0.18288)
		(layer "In11.Cu")
		(net "M_D_CPU0_SA_DQS_DP<4>")
	)
	(segment
		(start 345.975686 -263.238996)
		(end 345.97086 -263.241536)
		(width 0.088646)
		(layer "In11.Cu")
		(net "M_D_CPU0_SA_DQS_DP<4>")
	)
	(segment
		(start 294.71239 -274.240752)
		(end 294.45077 -273.979132)
		(width 0.18288)
		(layer "In11.Cu")
		(net "M_D_CPU0_SA_DQS_DP<4>")
	)
	(segment
		(start 266.9794 -274.886166)
		(end 266.240768 -274.886166)
		(width 0.18288)
		(layer "In11.Cu")
		(net "M_D_CPU0_SA_DQS_DP<4>")
	)
	(segment
		(start 346.662502 -262.96239)
		(end 346.237306 -263.204198)
		(width 0.088646)
		(layer "In11.Cu")
		(net "M_D_CPU0_SA_DQS_DP<4>")
	)
	(segment
		(start 265.88085 -275.246084)
		(end 264.999724 -275.246084)
		(width 0.18288)
		(layer "In11.Cu")
		(net "M_D_CPU0_SA_DQS_DP<4>")
	)
	(segment
		(start 295.111678 -274.240752)
		(end 294.71239 -274.240752)
		(width 0.18288)
		(layer "In11.Cu")
		(net "M_D_CPU0_SA_DQS_DP<4>")
	)
	(segment
		(start 270.898874 -275.67128)
		(end 269.280132 -275.67128)
		(width 0.18288)
		(layer "In11.Cu")
		(net "M_D_CPU0_SA_DQS_DP<4>")
	)
	(segment
		(start 346.032836 -263.245854)
		(end 345.975686 -263.238996)
		(width 0.088646)
		(layer "In11.Cu")
		(net "M_D_CPU0_SA_DQS_DP<4>")
	)
	(segment
		(start 280.28392 -273.95805)
		(end 280.001218 -274.240752)
		(width 0.18288)
		(layer "In11.Cu")
		(net "M_D_CPU0_SA_DQS_DP<4>")
	)
	(segment
		(start 266.240768 -274.886166)
		(end 265.88085 -275.246084)
		(width 0.18288)
		(layer "In11.Cu")
		(net "M_D_CPU0_SA_DQS_DP<4>")
	)
	(segment
		(start 273.701002 -274.166076)
		(end 273.209512 -274.657566)
		(width 0.18288)
		(layer "In11.Cu")
		(net "M_D_CPU0_SA_DQS_DP<4>")
	)
	(segment
		(start 342.971374 -263.368282)
		(end 342.96096 -263.362186)
		(width 0.088646)
		(layer "In11.Cu")
		(net "M_D_CPU0_SA_DQS_DP<4>")
	)
	(segment
		(start 307.438044 -272.87601)
		(end 306.959 -272.396966)
		(width 0.18288)
		(layer "In11.Cu")
		(net "M_D_CPU0_SA_DQS_DP<4>")
	)
	(segment
		(start 293.818056 -273.979132)
		(end 293.139622 -274.657566)
		(width 0.18288)
		(layer "In11.Cu")
		(net "M_D_CPU0_SA_DQS_DP<4>")
	)
	(segment
		(start 345.61526 -263.241536)
		(end 345.39174 -263.370314)
		(width 0.088646)
		(layer "In11.Cu")
		(net "M_D_CPU0_SA_DQS_DP<4>")
	)
	(segment
		(start 331.830426 -263.437878)
		(end 331.434694 -263.83361)
		(width 0.088646)
		(layer "In11.Cu")
		(net "M_D_CPU0_SA_DQS_DP<4>")
	)
	(segment
		(start 340.156546 -263.370822)
		(end 340.141814 -263.362186)
		(width 0.088646)
		(layer "In11.Cu")
		(net "M_D_CPU0_SA_DQS_DP<4>")
	)
	(segment
		(start 293.139622 -274.657566)
		(end 292.350952 -274.657566)
		(width 0.18288)
		(layer "In11.Cu")
		(net "M_D_CPU0_SA_DQS_DP<4>")
	)
	(segment
		(start 295.408858 -273.943572)
		(end 295.111678 -274.240752)
		(width 0.18288)
		(layer "In11.Cu")
		(net "M_D_CPU0_SA_DQS_DP<4>")
	)
	(segment
		(start 338.827618 -263.362186)
		(end 338.817204 -263.368282)
		(width 0.088646)
		(layer "In11.Cu")
		(net "M_D_CPU0_SA_DQS_DP<4>")
	)
	(segment
		(start 284.38602 -273.11223)
		(end 284.107382 -273.390868)
		(width 0.18288)
		(layer "In11.Cu")
		(net "M_D_CPU0_SA_DQS_DP<4>")
	)
	(segment
		(start 315.339476 -272.046446)
		(end 311.53227 -272.046446)
		(width 0.18288)
		(layer "In11.Cu")
		(net "M_D_CPU0_SA_DQS_DP<4>")
	)
	(segment
		(start 280.001218 -274.240752)
		(end 279.590246 -274.240752)
		(width 0.18288)
		(layer "In11.Cu")
		(net "M_D_CPU0_SA_DQS_DP<4>")
	)
	(segment
		(start 288.057082 -273.866864)
		(end 287.302448 -273.11223)
		(width 0.18288)
		(layer "In11.Cu")
		(net "M_D_CPU0_SA_DQS_DP<4>")
	)
	(segment
		(start 269.280132 -275.67128)
		(end 269.008606 -275.942806)
		(width 0.18288)
		(layer "In11.Cu")
		(net "M_D_CPU0_SA_DQS_DP<4>")
	)
	(segment
		(start 278.928068 -273.966686)
		(end 278.237188 -274.657566)
		(width 0.18288)
		(layer "In11.Cu")
		(net "M_D_CPU0_SA_DQS_DP<4>")
	)
	(segment
		(start 297.010836 -273.943572)
		(end 295.408858 -273.943572)
		(width 0.18288)
		(layer "In11.Cu")
		(net "M_D_CPU0_SA_DQS_DP<4>")
	)
	(segment
		(start 299.188378 -273.390868)
		(end 298.812458 -273.390868)
		(width 0.18288)
		(layer "In11.Cu")
		(net "M_D_CPU0_SA_DQS_DP<4>")
	)
	(segment
		(start 331.434694 -263.83361)
		(end 331.037184 -263.83361)
		(width 0.088646)
		(layer "In11.Cu")
		(net "M_D_CPU0_SA_DQS_DP<4>")
	)
	(segment
		(start 268.36116 -275.653754)
		(end 267.746988 -275.653754)
		(width 0.18288)
		(layer "In11.Cu")
		(net "M_D_CPU0_SA_DQS_DP<4>")
	)
	(segment
		(start 345.97086 -263.241536)
		(end 345.61526 -263.241536)
		(width 0.088646)
		(layer "In11.Cu")
		(net "M_D_CPU0_SA_DQS_DP<4>")
	)
	(segment
		(start 297.825922 -273.128486)
		(end 297.010836 -273.943572)
		(width 0.18288)
		(layer "In11.Cu")
		(net "M_D_CPU0_SA_DQS_DP<4>")
	)
	(segment
		(start 299.475652 -273.103594)
		(end 299.188378 -273.390868)
		(width 0.18288)
		(layer "In11.Cu")
		(net "M_D_CPU0_SA_DQS_DP<4>")
	)
	(segment
		(start 339.216746 -263.370822)
		(end 339.202014 -263.362186)
		(width 0.088646)
		(layer "In11.Cu")
		(net "M_D_CPU0_SA_DQS_DP<4>")
	)
	(segment
		(start 303.904904 -272.396966)
		(end 303.198276 -273.103594)
		(width 0.18288)
		(layer "In11.Cu")
		(net "M_D_CPU0_SA_DQS_DP<4>")
	)
	(segment
		(start 342.031828 -263.368282)
		(end 342.021414 -263.362186)
		(width 0.088646)
		(layer "In11.Cu")
		(net "M_D_CPU0_SA_DQS_DP<4>")
	)
	(segment
		(start 287.302448 -273.11223)
		(end 284.38602 -273.11223)
		(width 0.18288)
		(layer "In11.Cu")
		(net "M_D_CPU0_SA_DQS_DP<4>")
	)
	(segment
		(start 311.53227 -272.046446)
		(end 310.702706 -272.87601)
		(width 0.18288)
		(layer "In11.Cu")
		(net "M_D_CPU0_SA_DQS_DP<4>")
	)
	(segment
		(start 344.84056 -263.361932)
		(end 344.840814 -263.362186)
		(width 0.088646)
		(layer "In11.Cu")
		(net "M_D_CPU0_SA_DQS_DP<4>")
	)
	(segment
		(start 298.812458 -273.390868)
		(end 298.550076 -273.128486)
		(width 0.18288)
		(layer "In11.Cu")
		(net "M_D_CPU0_SA_DQS_DP<4>")
	)
	(segment
		(start 267.746988 -275.653754)
		(end 266.9794 -274.886166)
		(width 0.18288)
		(layer "In11.Cu")
		(net "M_D_CPU0_SA_DQS_DP<4>")
	)
	(segment
		(start 283.428948 -273.094958)
		(end 283.00553 -273.094958)
		(width 0.18288)
		(layer "In11.Cu")
		(net "M_D_CPU0_SA_DQS_DP<4>")
	)
	(segment
		(start 276.824694 -274.166076)
		(end 273.701002 -274.166076)
		(width 0.18288)
		(layer "In11.Cu")
		(net "M_D_CPU0_SA_DQS_DP<4>")
	)
	(segment
		(start 282.142438 -273.95805)
		(end 280.28392 -273.95805)
		(width 0.18288)
		(layer "In11.Cu")
		(net "M_D_CPU0_SA_DQS_DP<4>")
	)
	(segment
		(start 330.97724 -263.893554)
		(end 323.492368 -263.893554)
		(width 0.18288)
		(layer "In11.Cu")
		(net "M_D_CPU0_SA_DQS_DP<4>")
	)
	(segment
		(start 306.959 -272.396966)
		(end 303.904904 -272.396966)
		(width 0.18288)
		(layer "In11.Cu")
		(net "M_D_CPU0_SA_DQS_DP<4>")
	)
	(segment
		(start 303.198276 -273.103594)
		(end 299.475652 -273.103594)
		(width 0.18288)
		(layer "In11.Cu")
		(net "M_D_CPU0_SA_DQS_DP<4>")
	)
	(segment
		(start 273.209512 -274.657566)
		(end 271.912588 -274.657566)
		(width 0.18288)
		(layer "In11.Cu")
		(net "M_D_CPU0_SA_DQS_DP<4>")
	)
	(segment
		(start 341.096346 -263.370822)
		(end 341.081614 -263.362186)
		(width 0.088646)
		(layer "In11.Cu")
		(net "M_D_CPU0_SA_DQS_DP<4>")
	)
	(segment
		(start 283.724858 -273.390868)
		(end 283.428948 -273.094958)
		(width 0.18288)
		(layer "In11.Cu")
		(net "M_D_CPU0_SA_DQS_DP<4>")
	)
	(segment
		(start 268.650212 -275.942806)
		(end 268.36116 -275.653754)
		(width 0.18288)
		(layer "In11.Cu")
		(net "M_D_CPU0_SA_DQS_DP<4>")
	)
	(segment
		(start 271.912588 -274.657566)
		(end 270.898874 -275.67128)
		(width 0.18288)
		(layer "In11.Cu")
		(net "M_D_CPU0_SA_DQS_DP<4>")
	)
	(segment
		(start 283.00553 -273.094958)
		(end 282.142438 -273.95805)
		(width 0.18288)
		(layer "In11.Cu")
		(net "M_D_CPU0_SA_DQS_DP<4>")
	)
	(segment
		(start 284.107382 -273.390868)
		(end 283.724858 -273.390868)
		(width 0.18288)
		(layer "In11.Cu")
		(net "M_D_CPU0_SA_DQS_DP<4>")
	)
	(segment
		(start 343.915746 -263.370822)
		(end 343.901014 -263.362186)
		(width 0.088646)
		(layer "In11.Cu")
		(net "M_D_CPU0_SA_DQS_DP<4>")
	)
	(segment
		(start 279.31618 -273.966686)
		(end 278.928068 -273.966686)
		(width 0.18288)
		(layer "In11.Cu")
		(net "M_D_CPU0_SA_DQS_DP<4>")
	)
	(segment
		(start 264.999724 -275.246084)
		(end 264.729214 -275.516594)
		(width 0.18288)
		(layer "In11.Cu")
		(net "M_D_CPU0_SA_DQS_DP<4>")
	)
	(segment
		(start 331.966062 -263.437878)
		(end 331.830426 -263.437878)
		(width 0.088646)
		(layer "In11.Cu")
		(net "M_D_CPU0_SA_DQS_DP<4>")
	)
	(segment
		(start 279.590246 -274.240752)
		(end 279.31618 -273.966686)
		(width 0.18288)
		(layer "In11.Cu")
		(net "M_D_CPU0_SA_DQS_DP<4>")
	)
	(segment
		(start 310.702706 -272.87601)
		(end 307.438044 -272.87601)
		(width 0.18288)
		(layer "In11.Cu")
		(net "M_D_CPU0_SA_DQS_DP<4>")
	)
	(segment
		(start 323.492368 -263.893554)
		(end 315.339476 -272.046446)
		(width 0.18288)
		(layer "In11.Cu")
		(net "M_D_CPU0_SA_DQS_DP<4>")
	)
	(arc
		(start 342.586564 -263.362186)
		(mid 342.310005 -263.437895)
		(end 342.031828 -263.368282)
		(width 0.088646)
		(layer "In11.Cu")
		(net "M_D_CPU0_SA_DQS_DP<4>")
	)
	(arc
		(start 337.32216 -263.362186)
		(mid 337.134962 -263.312043)
		(end 336.947764 -263.362186)
		(width 0.088646)
		(layer "In11.Cu")
		(net "M_D_CPU0_SA_DQS_DP<4>")
	)
	(arc
		(start 343.901014 -263.362186)
		(mid 343.713816 -263.312043)
		(end 343.526618 -263.362186)
		(width 0.088646)
		(layer "In11.Cu")
		(net "M_D_CPU0_SA_DQS_DP<4>")
	)
	(arc
		(start 342.96096 -263.362186)
		(mid 342.773762 -263.312043)
		(end 342.586564 -263.362186)
		(width 0.088646)
		(layer "In11.Cu")
		(net "M_D_CPU0_SA_DQS_DP<4>")
	)
	(arc
		(start 334.128364 -263.362186)
		(mid 333.845662 -263.437928)
		(end 333.56296 -263.362186)
		(width 0.088646)
		(layer "In11.Cu")
		(net "M_D_CPU0_SA_DQS_DP<4>")
	)
	(arc
		(start 332.248764 -263.362186)
		(mid 332.112398 -263.418664)
		(end 331.966062 -263.437878)
		(width 0.088646)
		(layer "In11.Cu")
		(net "M_D_CPU0_SA_DQS_DP<4>")
	)
	(arc
		(start 333.188564 -263.362186)
		(mid 332.905862 -263.437928)
		(end 332.62316 -263.362186)
		(width 0.088646)
		(layer "In11.Cu")
		(net "M_D_CPU0_SA_DQS_DP<4>")
	)
	(arc
		(start 340.141814 -263.362186)
		(mid 339.954616 -263.312043)
		(end 339.767418 -263.362186)
		(width 0.088646)
		(layer "In11.Cu")
		(net "M_D_CPU0_SA_DQS_DP<4>")
	)
	(arc
		(start 344.840814 -263.362186)
		(mid 344.653616 -263.312043)
		(end 344.466418 -263.362186)
		(width 0.088646)
		(layer "In11.Cu")
		(net "M_D_CPU0_SA_DQS_DP<4>")
	)
	(arc
		(start 336.947764 -263.362186)
		(mid 336.665062 -263.437928)
		(end 336.38236 -263.362186)
		(width 0.088646)
		(layer "In11.Cu")
		(net "M_D_CPU0_SA_DQS_DP<4>")
	)
	(arc
		(start 334.50276 -263.362186)
		(mid 334.315562 -263.312043)
		(end 334.128364 -263.362186)
		(width 0.088646)
		(layer "In11.Cu")
		(net "M_D_CPU0_SA_DQS_DP<4>")
	)
	(arc
		(start 339.202014 -263.362186)
		(mid 339.014816 -263.312043)
		(end 338.827618 -263.362186)
		(width 0.088646)
		(layer "In11.Cu")
		(net "M_D_CPU0_SA_DQS_DP<4>")
	)
	(arc
		(start 339.767418 -263.362186)
		(mid 339.493189 -263.438111)
		(end 339.216746 -263.370822)
		(width 0.088646)
		(layer "In11.Cu")
		(net "M_D_CPU0_SA_DQS_DP<4>")
	)
	(arc
		(start 343.526618 -263.362186)
		(mid 343.249805 -263.438022)
		(end 342.971374 -263.368282)
		(width 0.088646)
		(layer "In11.Cu")
		(net "M_D_CPU0_SA_DQS_DP<4>")
	)
	(arc
		(start 338.817204 -263.368282)
		(mid 338.538772 -263.438096)
		(end 338.26196 -263.362186)
		(width 0.088646)
		(layer "In11.Cu")
		(net "M_D_CPU0_SA_DQS_DP<4>")
	)
	(arc
		(start 336.007964 -263.362186)
		(mid 335.725262 -263.437928)
		(end 335.44256 -263.362186)
		(width 0.088646)
		(layer "In11.Cu")
		(net "M_D_CPU0_SA_DQS_DP<4>")
	)
	(arc
		(start 338.26196 -263.362186)
		(mid 338.074762 -263.312043)
		(end 337.887564 -263.362186)
		(width 0.088646)
		(layer "In11.Cu")
		(net "M_D_CPU0_SA_DQS_DP<4>")
	)
	(arc
		(start 341.647018 -263.362186)
		(mid 341.372789 -263.438111)
		(end 341.096346 -263.370822)
		(width 0.088646)
		(layer "In11.Cu")
		(net "M_D_CPU0_SA_DQS_DP<4>")
	)
	(arc
		(start 335.44256 -263.362186)
		(mid 335.255362 -263.312043)
		(end 335.068164 -263.362186)
		(width 0.088646)
		(layer "In11.Cu")
		(net "M_D_CPU0_SA_DQS_DP<4>")
	)
	(arc
		(start 337.887564 -263.362186)
		(mid 337.604862 -263.437928)
		(end 337.32216 -263.362186)
		(width 0.088646)
		(layer "In11.Cu")
		(net "M_D_CPU0_SA_DQS_DP<4>")
	)
	(arc
		(start 347.002862 -262.872474)
		(mid 346.826841 -262.895311)
		(end 346.662502 -262.96239)
		(width 0.088646)
		(layer "In11.Cu")
		(net "M_D_CPU0_SA_DQS_DP<4>")
	)
	(arc
		(start 340.707218 -263.362186)
		(mid 340.432989 -263.438111)
		(end 340.156546 -263.370822)
		(width 0.088646)
		(layer "In11.Cu")
		(net "M_D_CPU0_SA_DQS_DP<4>")
	)
	(arc
		(start 345.39174 -263.370314)
		(mid 345.115075 -263.437785)
		(end 344.84056 -263.361932)
		(width 0.088646)
		(layer "In11.Cu")
		(net "M_D_CPU0_SA_DQS_DP<4>")
	)
	(arc
		(start 346.237306 -263.204198)
		(mid 346.138464 -263.241708)
		(end 346.032836 -263.245854)
		(width 0.088646)
		(layer "In11.Cu")
		(net "M_D_CPU0_SA_DQS_DP<4>")
	)
	(arc
		(start 336.38236 -263.362186)
		(mid 336.195162 -263.312043)
		(end 336.007964 -263.362186)
		(width 0.088646)
		(layer "In11.Cu")
		(net "M_D_CPU0_SA_DQS_DP<4>")
	)
	(arc
		(start 341.081614 -263.362186)
		(mid 340.894416 -263.312043)
		(end 340.707218 -263.362186)
		(width 0.088646)
		(layer "In11.Cu")
		(net "M_D_CPU0_SA_DQS_DP<4>")
	)
	(arc
		(start 335.068164 -263.362186)
		(mid 334.785462 -263.437928)
		(end 334.50276 -263.362186)
		(width 0.088646)
		(layer "In11.Cu")
		(net "M_D_CPU0_SA_DQS_DP<4>")
	)
	(arc
		(start 332.62316 -263.362186)
		(mid 332.435962 -263.312043)
		(end 332.248764 -263.362186)
		(width 0.088646)
		(layer "In11.Cu")
		(net "M_D_CPU0_SA_DQS_DP<4>")
	)
	(arc
		(start 333.56296 -263.362186)
		(mid 333.375762 -263.312043)
		(end 333.188564 -263.362186)
		(width 0.088646)
		(layer "In11.Cu")
		(net "M_D_CPU0_SA_DQS_DP<4>")
	)
	(arc
		(start 342.021414 -263.362186)
		(mid 341.834216 -263.312043)
		(end 341.647018 -263.362186)
		(width 0.088646)
		(layer "In11.Cu")
		(net "M_D_CPU0_SA_DQS_DP<4>")
	)
	(arc
		(start 344.466418 -263.362186)
		(mid 344.192189 -263.438111)
		(end 343.915746 -263.370822)
		(width 0.088646)
		(layer "In11.Cu")
		(net "M_D_CPU0_SA_DQS_DP<4>")
	)
	(segment
		(start 261.53364 -285.291784)
		(end 261.381494 -285.291784)
		(width 0.20066)
		(layer "F.Cu")
		(net "M_D_CPU0_SA_DQS_DP<3>")
	)
	(segment
		(start 262.814562 -284.605476)
		(end 262.54583 -284.605476)
		(width 0.20066)
		(layer "F.Cu")
		(net "M_D_CPU0_SA_DQS_DP<3>")
	)
	(segment
		(start 256.879598 -284.605476)
		(end 256.618486 -284.866588)
		(width 0.20066)
		(layer "F.Cu")
		(net "M_D_CPU0_SA_DQS_DP<3>")
	)
	(segment
		(start 259.302758 -285.291784)
		(end 259.065776 -285.291784)
		(width 0.101854)
		(layer "F.Cu")
		(net "M_D_CPU0_SA_DQS_DP<3>")
	)
	(segment
		(start 258.567682 -285.030672)
		(end 257.940556 -285.030672)
		(width 0.20066)
		(layer "F.Cu")
		(net "M_D_CPU0_SA_DQS_DP<3>")
	)
	(segment
		(start 259.056378 -285.301182)
		(end 258.838192 -285.301182)
		(width 0.20066)
		(layer "F.Cu")
		(net "M_D_CPU0_SA_DQS_DP<3>")
	)
	(segment
		(start 262.54583 -284.605476)
		(end 262.120634 -285.030672)
		(width 0.20066)
		(layer "F.Cu")
		(net "M_D_CPU0_SA_DQS_DP<3>")
	)
	(segment
		(start 256.618486 -284.866588)
		(end 256.080514 -284.866588)
		(width 0.20066)
		(layer "F.Cu")
		(net "M_D_CPU0_SA_DQS_DP<3>")
	)
	(segment
		(start 259.065776 -285.291784)
		(end 259.056378 -285.301182)
		(width 0.101854)
		(layer "F.Cu")
		(net "M_D_CPU0_SA_DQS_DP<3>")
	)
	(segment
		(start 261.794752 -285.030672)
		(end 261.53364 -285.291784)
		(width 0.20066)
		(layer "F.Cu")
		(net "M_D_CPU0_SA_DQS_DP<3>")
	)
	(segment
		(start 347.003116 -267.219938)
		(end 347.002862 -267.220192)
		(width 0.20066)
		(layer "F.Cu")
		(net "M_D_CPU0_SA_DQS_DP<3>")
	)
	(segment
		(start 262.120634 -285.030672)
		(end 261.794752 -285.030672)
		(width 0.20066)
		(layer "F.Cu")
		(net "M_D_CPU0_SA_DQS_DP<3>")
	)
	(segment
		(start 264.729214 -284.866588)
		(end 263.624314 -284.866588)
		(width 0.20066)
		(layer "F.Cu")
		(net "M_D_CPU0_SA_DQS_DP<3>")
	)
	(segment
		(start 347.002862 -267.220192)
		(end 347.002862 -267.755878)
		(width 0.20066)
		(layer "F.Cu")
		(net "M_D_CPU0_SA_DQS_DP<3>")
	)
	(segment
		(start 261.381494 -285.291784)
		(end 261.058152 -285.291784)
		(width 0.101854)
		(layer "F.Cu")
		(net "M_D_CPU0_SA_DQS_DP<3>")
	)
	(segment
		(start 257.940556 -285.030672)
		(end 257.30454 -284.605476)
		(width 0.20066)
		(layer "F.Cu")
		(net "M_D_CPU0_SA_DQS_DP<3>")
	)
	(segment
		(start 263.624314 -284.866588)
		(end 263.075674 -284.866588)
		(width 0.20066)
		(layer "F.Cu")
		(net "M_D_CPU0_SA_DQS_DP<3>")
	)
	(segment
		(start 258.838192 -285.301182)
		(end 258.567682 -285.030672)
		(width 0.20066)
		(layer "F.Cu")
		(net "M_D_CPU0_SA_DQS_DP<3>")
	)
	(segment
		(start 261.058152 -285.291784)
		(end 259.302758 -285.291784)
		(width 0.1016)
		(layer "F.Cu")
		(net "M_D_CPU0_SA_DQS_DP<3>")
	)
	(segment
		(start 257.30454 -284.605476)
		(end 256.879598 -284.605476)
		(width 0.20066)
		(layer "F.Cu")
		(net "M_D_CPU0_SA_DQS_DP<3>")
	)
	(segment
		(start 263.075674 -284.866588)
		(end 262.814562 -284.605476)
		(width 0.20066)
		(layer "F.Cu")
		(net "M_D_CPU0_SA_DQS_DP<3>")
	)
	(segment
		(start 293.020496 -285.016956)
		(end 291.314124 -284.310074)
		(width 0.18288)
		(layer "In11.Cu")
		(net "M_D_CPU0_SA_DQS_DP<3>")
	)
	(segment
		(start 265.740642 -284.592014)
		(end 265.003788 -284.592014)
		(width 0.18288)
		(layer "In11.Cu")
		(net "M_D_CPU0_SA_DQS_DP<3>")
	)
	(segment
		(start 345.975686 -268.1224)
		(end 345.97086 -268.12494)
		(width 0.088646)
		(layer "In11.Cu")
		(net "M_D_CPU0_SA_DQS_DP<3>")
	)
	(segment
		(start 280.295858 -285.853632)
		(end 280.006806 -286.142684)
		(width 0.18288)
		(layer "In11.Cu")
		(net "M_D_CPU0_SA_DQS_DP<3>")
	)
	(segment
		(start 291.314124 -284.310074)
		(end 286.606996 -284.310074)
		(width 0.18288)
		(layer "In11.Cu")
		(net "M_D_CPU0_SA_DQS_DP<3>")
	)
	(segment
		(start 283.27477 -285.030164)
		(end 281.288998 -285.853632)
		(width 0.18288)
		(layer "In11.Cu")
		(net "M_D_CPU0_SA_DQS_DP<3>")
	)
	(segment
		(start 267.960856 -285.000192)
		(end 267.269722 -284.713934)
		(width 0.18288)
		(layer "In11.Cu")
		(net "M_D_CPU0_SA_DQS_DP<3>")
	)
	(segment
		(start 331.92466 -269.080996)
		(end 331.616812 -269.388844)
		(width 0.088646)
		(layer "In11.Cu")
		(net "M_D_CPU0_SA_DQS_DP<3>")
	)
	(segment
		(start 283.726636 -285.2928)
		(end 283.464 -285.030164)
		(width 0.18288)
		(layer "In11.Cu")
		(net "M_D_CPU0_SA_DQS_DP<3>")
	)
	(segment
		(start 307.574188 -282.658566)
		(end 307.094636 -283.138118)
		(width 0.18288)
		(layer "In11.Cu")
		(net "M_D_CPU0_SA_DQS_DP<3>")
	)
	(segment
		(start 267.269722 -284.713934)
		(end 266.975082 -284.419294)
		(width 0.18288)
		(layer "In11.Cu")
		(net "M_D_CPU0_SA_DQS_DP<3>")
	)
	(segment
		(start 284.91053 -285.012892)
		(end 284.38094 -285.012892)
		(width 0.18288)
		(layer "In11.Cu")
		(net "M_D_CPU0_SA_DQS_DP<3>")
	)
	(segment
		(start 297.294046 -285.872428)
		(end 295.363646 -285.872428)
		(width 0.18288)
		(layer "In11.Cu")
		(net "M_D_CPU0_SA_DQS_DP<3>")
	)
	(segment
		(start 326.07885 -269.908274)
		(end 314.62853 -281.358594)
		(width 0.18288)
		(layer "In11.Cu")
		(net "M_D_CPU0_SA_DQS_DP<3>")
	)
	(segment
		(start 301.764954 -283.949648)
		(end 300.587918 -284.437836)
		(width 0.18288)
		(layer "In11.Cu")
		(net "M_D_CPU0_SA_DQS_DP<3>")
	)
	(segment
		(start 338.827618 -268.245336)
		(end 338.817204 -268.251432)
		(width 0.088646)
		(layer "In11.Cu")
		(net "M_D_CPU0_SA_DQS_DP<3>")
	)
	(segment
		(start 298.140882 -285.025592)
		(end 297.294046 -285.872428)
		(width 0.18288)
		(layer "In11.Cu")
		(net "M_D_CPU0_SA_DQS_DP<3>")
	)
	(segment
		(start 332.205838 -268.324076)
		(end 332.205838 -268.551914)
		(width 0.088646)
		(layer "In11.Cu")
		(net "M_D_CPU0_SA_DQS_DP<3>")
	)
	(segment
		(start 266.15771 -284.419294)
		(end 265.740642 -284.592014)
		(width 0.18288)
		(layer "In11.Cu")
		(net "M_D_CPU0_SA_DQS_DP<3>")
	)
	(segment
		(start 265.003788 -284.592014)
		(end 264.729214 -284.866588)
		(width 0.18288)
		(layer "In11.Cu")
		(net "M_D_CPU0_SA_DQS_DP<3>")
	)
	(segment
		(start 295.363646 -285.872428)
		(end 295.095422 -286.140652)
		(width 0.18288)
		(layer "In11.Cu")
		(net "M_D_CPU0_SA_DQS_DP<3>")
	)
	(segment
		(start 342.971374 -268.251432)
		(end 342.96096 -268.245336)
		(width 0.088646)
		(layer "In11.Cu")
		(net "M_D_CPU0_SA_DQS_DP<3>")
	)
	(segment
		(start 299.191934 -285.290514)
		(end 298.81195 -285.290514)
		(width 0.18288)
		(layer "In11.Cu")
		(net "M_D_CPU0_SA_DQS_DP<3>")
	)
	(segment
		(start 278.862536 -285.880302)
		(end 277.331424 -284.34919)
		(width 0.18288)
		(layer "In11.Cu")
		(net "M_D_CPU0_SA_DQS_DP<3>")
	)
	(segment
		(start 331.616812 -269.388844)
		(end 331.616812 -269.614142)
		(width 0.088646)
		(layer "In11.Cu")
		(net "M_D_CPU0_SA_DQS_DP<3>")
	)
	(segment
		(start 341.096346 -268.253972)
		(end 341.081614 -268.245336)
		(width 0.088646)
		(layer "In11.Cu")
		(net "M_D_CPU0_SA_DQS_DP<3>")
	)
	(segment
		(start 331.92466 -268.833092)
		(end 331.92466 -269.080996)
		(width 0.088646)
		(layer "In11.Cu")
		(net "M_D_CPU0_SA_DQS_DP<3>")
	)
	(segment
		(start 346.032836 -268.129258)
		(end 345.975686 -268.1224)
		(width 0.088646)
		(layer "In11.Cu")
		(net "M_D_CPU0_SA_DQS_DP<3>")
	)
	(segment
		(start 310.09336 -282.492958)
		(end 309.692802 -282.658566)
		(width 0.18288)
		(layer "In11.Cu")
		(net "M_D_CPU0_SA_DQS_DP<3>")
	)
	(segment
		(start 293.871904 -285.86811)
		(end 293.021004 -285.017464)
		(width 0.18288)
		(layer "In11.Cu")
		(net "M_D_CPU0_SA_DQS_DP<3>")
	)
	(segment
		(start 281.288998 -285.853632)
		(end 280.295858 -285.853632)
		(width 0.18288)
		(layer "In11.Cu")
		(net "M_D_CPU0_SA_DQS_DP<3>")
	)
	(segment
		(start 269.295118 -285.012892)
		(end 269.01521 -285.2928)
		(width 0.18288)
		(layer "In11.Cu")
		(net "M_D_CPU0_SA_DQS_DP<3>")
	)
	(segment
		(start 283.464 -285.030164)
		(end 283.27477 -285.030164)
		(width 0.18288)
		(layer "In11.Cu")
		(net "M_D_CPU0_SA_DQS_DP<3>")
	)
	(segment
		(start 314.62853 -281.358594)
		(end 311.227724 -281.358594)
		(width 0.18288)
		(layer "In11.Cu")
		(net "M_D_CPU0_SA_DQS_DP<3>")
	)
	(segment
		(start 343.915746 -268.253972)
		(end 343.901014 -268.245336)
		(width 0.088646)
		(layer "In11.Cu")
		(net "M_D_CPU0_SA_DQS_DP<3>")
	)
	(segment
		(start 299.460412 -285.022036)
		(end 299.191934 -285.290514)
		(width 0.18288)
		(layer "In11.Cu")
		(net "M_D_CPU0_SA_DQS_DP<3>")
	)
	(segment
		(start 286.606996 -284.310074)
		(end 284.91053 -285.012892)
		(width 0.18288)
		(layer "In11.Cu")
		(net "M_D_CPU0_SA_DQS_DP<3>")
	)
	(segment
		(start 279.626314 -286.142684)
		(end 279.363932 -285.880302)
		(width 0.18288)
		(layer "In11.Cu")
		(net "M_D_CPU0_SA_DQS_DP<3>")
	)
	(segment
		(start 293.021004 -285.017464)
		(end 293.020496 -285.016956)
		(width 0.18288)
		(layer "In11.Cu")
		(net "M_D_CPU0_SA_DQS_DP<3>")
	)
	(segment
		(start 294.43934 -285.86811)
		(end 293.871904 -285.86811)
		(width 0.18288)
		(layer "In11.Cu")
		(net "M_D_CPU0_SA_DQS_DP<3>")
	)
	(segment
		(start 280.006806 -286.142684)
		(end 279.626314 -286.142684)
		(width 0.18288)
		(layer "In11.Cu")
		(net "M_D_CPU0_SA_DQS_DP<3>")
	)
	(segment
		(start 268.34084 -285.000192)
		(end 267.960856 -285.000192)
		(width 0.18288)
		(layer "In11.Cu")
		(net "M_D_CPU0_SA_DQS_DP<3>")
	)
	(segment
		(start 269.01521 -285.2928)
		(end 268.633448 -285.2928)
		(width 0.18288)
		(layer "In11.Cu")
		(net "M_D_CPU0_SA_DQS_DP<3>")
	)
	(segment
		(start 272.296128 -285.012892)
		(end 269.295118 -285.012892)
		(width 0.18288)
		(layer "In11.Cu")
		(net "M_D_CPU0_SA_DQS_DP<3>")
	)
	(segment
		(start 345.61526 -268.12494)
		(end 345.39174 -268.253718)
		(width 0.088646)
		(layer "In11.Cu")
		(net "M_D_CPU0_SA_DQS_DP<3>")
	)
	(segment
		(start 309.692802 -282.658566)
		(end 307.574188 -282.658566)
		(width 0.18288)
		(layer "In11.Cu")
		(net "M_D_CPU0_SA_DQS_DP<3>")
	)
	(segment
		(start 311.227724 -281.358594)
		(end 310.09336 -282.492958)
		(width 0.18288)
		(layer "In11.Cu")
		(net "M_D_CPU0_SA_DQS_DP<3>")
	)
	(segment
		(start 284.101032 -285.2928)
		(end 283.726636 -285.2928)
		(width 0.18288)
		(layer "In11.Cu")
		(net "M_D_CPU0_SA_DQS_DP<3>")
	)
	(segment
		(start 344.84056 -268.245336)
		(end 344.840814 -268.245336)
		(width 0.088646)
		(layer "In11.Cu")
		(net "M_D_CPU0_SA_DQS_DP<3>")
	)
	(segment
		(start 345.97086 -268.12494)
		(end 345.61526 -268.12494)
		(width 0.088646)
		(layer "In11.Cu")
		(net "M_D_CPU0_SA_DQS_DP<3>")
	)
	(segment
		(start 330.92644 -269.908274)
		(end 326.07885 -269.908274)
		(width 0.18288)
		(layer "In11.Cu")
		(net "M_D_CPU0_SA_DQS_DP<3>")
	)
	(segment
		(start 331.616812 -269.614142)
		(end 331.382624 -269.84833)
		(width 0.088646)
		(layer "In11.Cu")
		(net "M_D_CPU0_SA_DQS_DP<3>")
	)
	(segment
		(start 332.205838 -268.551914)
		(end 331.92466 -268.833092)
		(width 0.088646)
		(layer "In11.Cu")
		(net "M_D_CPU0_SA_DQS_DP<3>")
	)
	(segment
		(start 266.975082 -284.419294)
		(end 266.15771 -284.419294)
		(width 0.18288)
		(layer "In11.Cu")
		(net "M_D_CPU0_SA_DQS_DP<3>")
	)
	(segment
		(start 300.587918 -284.437836)
		(end 300.003464 -285.022036)
		(width 0.18288)
		(layer "In11.Cu")
		(net "M_D_CPU0_SA_DQS_DP<3>")
	)
	(segment
		(start 302.54575 -283.949648)
		(end 301.764954 -283.949648)
		(width 0.18288)
		(layer "In11.Cu")
		(net "M_D_CPU0_SA_DQS_DP<3>")
	)
	(segment
		(start 298.547028 -285.025592)
		(end 298.140882 -285.025592)
		(width 0.18288)
		(layer "In11.Cu")
		(net "M_D_CPU0_SA_DQS_DP<3>")
	)
	(segment
		(start 346.662502 -267.845794)
		(end 346.237306 -268.087602)
		(width 0.088646)
		(layer "In11.Cu")
		(net "M_D_CPU0_SA_DQS_DP<3>")
	)
	(segment
		(start 294.711882 -286.140652)
		(end 294.43934 -285.86811)
		(width 0.18288)
		(layer "In11.Cu")
		(net "M_D_CPU0_SA_DQS_DP<3>")
	)
	(segment
		(start 342.031828 -268.251432)
		(end 342.021414 -268.245336)
		(width 0.088646)
		(layer "In11.Cu")
		(net "M_D_CPU0_SA_DQS_DP<3>")
	)
	(segment
		(start 300.003464 -285.022036)
		(end 299.460412 -285.022036)
		(width 0.18288)
		(layer "In11.Cu")
		(net "M_D_CPU0_SA_DQS_DP<3>")
	)
	(segment
		(start 284.38094 -285.012892)
		(end 284.101032 -285.2928)
		(width 0.18288)
		(layer "In11.Cu")
		(net "M_D_CPU0_SA_DQS_DP<3>")
	)
	(segment
		(start 304.50536 -283.138118)
		(end 302.54575 -283.949648)
		(width 0.18288)
		(layer "In11.Cu")
		(net "M_D_CPU0_SA_DQS_DP<3>")
	)
	(segment
		(start 295.095422 -286.140652)
		(end 294.711882 -286.140652)
		(width 0.18288)
		(layer "In11.Cu")
		(net "M_D_CPU0_SA_DQS_DP<3>")
	)
	(segment
		(start 307.094636 -283.138118)
		(end 304.50536 -283.138118)
		(width 0.18288)
		(layer "In11.Cu")
		(net "M_D_CPU0_SA_DQS_DP<3>")
	)
	(segment
		(start 339.216746 -268.253972)
		(end 339.202014 -268.245336)
		(width 0.088646)
		(layer "In11.Cu")
		(net "M_D_CPU0_SA_DQS_DP<3>")
	)
	(segment
		(start 298.81195 -285.290514)
		(end 298.547028 -285.025592)
		(width 0.18288)
		(layer "In11.Cu")
		(net "M_D_CPU0_SA_DQS_DP<3>")
	)
	(segment
		(start 330.986384 -269.84833)
		(end 330.92644 -269.908274)
		(width 0.088646)
		(layer "In11.Cu")
		(net "M_D_CPU0_SA_DQS_DP<3>")
	)
	(segment
		(start 331.382624 -269.84833)
		(end 330.986384 -269.84833)
		(width 0.088646)
		(layer "In11.Cu")
		(net "M_D_CPU0_SA_DQS_DP<3>")
	)
	(segment
		(start 279.363932 -285.880302)
		(end 278.862536 -285.880302)
		(width 0.18288)
		(layer "In11.Cu")
		(net "M_D_CPU0_SA_DQS_DP<3>")
	)
	(segment
		(start 273.897598 -284.34919)
		(end 272.296128 -285.012892)
		(width 0.18288)
		(layer "In11.Cu")
		(net "M_D_CPU0_SA_DQS_DP<3>")
	)
	(segment
		(start 268.633448 -285.2928)
		(end 268.34084 -285.000192)
		(width 0.18288)
		(layer "In11.Cu")
		(net "M_D_CPU0_SA_DQS_DP<3>")
	)
	(segment
		(start 277.331424 -284.34919)
		(end 273.897598 -284.34919)
		(width 0.18288)
		(layer "In11.Cu")
		(net "M_D_CPU0_SA_DQS_DP<3>")
	)
	(segment
		(start 340.156546 -268.253972)
		(end 340.141814 -268.245336)
		(width 0.088646)
		(layer "In11.Cu")
		(net "M_D_CPU0_SA_DQS_DP<3>")
	)
	(arc
		(start 344.466418 -268.245336)
		(mid 344.192219 -268.321171)
		(end 343.915746 -268.253972)
		(width 0.088646)
		(layer "In11.Cu")
		(net "M_D_CPU0_SA_DQS_DP<3>")
	)
	(arc
		(start 335.44256 -268.245336)
		(mid 335.255362 -268.195193)
		(end 335.068164 -268.245336)
		(width 0.088646)
		(layer "In11.Cu")
		(net "M_D_CPU0_SA_DQS_DP<3>")
	)
	(arc
		(start 333.214726 -268.230858)
		(mid 332.93742 -268.301752)
		(end 332.65364 -268.264386)
		(width 0.088646)
		(layer "In11.Cu")
		(net "M_D_CPU0_SA_DQS_DP<3>")
	)
	(arc
		(start 338.26196 -268.245336)
		(mid 338.074762 -268.195193)
		(end 337.887564 -268.245336)
		(width 0.088646)
		(layer "In11.Cu")
		(net "M_D_CPU0_SA_DQS_DP<3>")
	)
	(arc
		(start 347.002862 -267.755878)
		(mid 346.826841 -267.778715)
		(end 346.662502 -267.845794)
		(width 0.088646)
		(layer "In11.Cu")
		(net "M_D_CPU0_SA_DQS_DP<3>")
	)
	(arc
		(start 341.081614 -268.245336)
		(mid 340.894416 -268.195193)
		(end 340.707218 -268.245336)
		(width 0.088646)
		(layer "In11.Cu")
		(net "M_D_CPU0_SA_DQS_DP<3>")
	)
	(arc
		(start 343.901014 -268.245336)
		(mid 343.713816 -268.195193)
		(end 343.526618 -268.245336)
		(width 0.088646)
		(layer "In11.Cu")
		(net "M_D_CPU0_SA_DQS_DP<3>")
	)
	(arc
		(start 342.96096 -268.245336)
		(mid 342.773762 -268.195193)
		(end 342.586564 -268.245336)
		(width 0.088646)
		(layer "In11.Cu")
		(net "M_D_CPU0_SA_DQS_DP<3>")
	)
	(arc
		(start 346.237306 -268.087602)
		(mid 346.138464 -268.125112)
		(end 346.032836 -268.129258)
		(width 0.088646)
		(layer "In11.Cu")
		(net "M_D_CPU0_SA_DQS_DP<3>")
	)
	(arc
		(start 345.39174 -268.253718)
		(mid 345.115075 -268.321189)
		(end 344.84056 -268.245336)
		(width 0.088646)
		(layer "In11.Cu")
		(net "M_D_CPU0_SA_DQS_DP<3>")
	)
	(arc
		(start 336.007964 -268.245336)
		(mid 335.725262 -268.321112)
		(end 335.44256 -268.245336)
		(width 0.088646)
		(layer "In11.Cu")
		(net "M_D_CPU0_SA_DQS_DP<3>")
	)
	(arc
		(start 341.647018 -268.245336)
		(mid 341.372819 -268.321171)
		(end 341.096346 -268.253972)
		(width 0.088646)
		(layer "In11.Cu")
		(net "M_D_CPU0_SA_DQS_DP<3>")
	)
	(arc
		(start 337.887564 -268.245336)
		(mid 337.604862 -268.321112)
		(end 337.32216 -268.245336)
		(width 0.088646)
		(layer "In11.Cu")
		(net "M_D_CPU0_SA_DQS_DP<3>")
	)
	(arc
		(start 338.817204 -268.251432)
		(mid 338.538772 -268.321278)
		(end 338.26196 -268.245336)
		(width 0.088646)
		(layer "In11.Cu")
		(net "M_D_CPU0_SA_DQS_DP<3>")
	)
	(arc
		(start 334.128364 -268.245336)
		(mid 333.845662 -268.321112)
		(end 333.56296 -268.245336)
		(width 0.088646)
		(layer "In11.Cu")
		(net "M_D_CPU0_SA_DQS_DP<3>")
	)
	(arc
		(start 343.526618 -268.245336)
		(mid 343.249805 -268.321206)
		(end 342.971374 -268.251432)
		(width 0.088646)
		(layer "In11.Cu")
		(net "M_D_CPU0_SA_DQS_DP<3>")
	)
	(arc
		(start 340.707218 -268.245336)
		(mid 340.433019 -268.321171)
		(end 340.156546 -268.253972)
		(width 0.088646)
		(layer "In11.Cu")
		(net "M_D_CPU0_SA_DQS_DP<3>")
	)
	(arc
		(start 340.141814 -268.245336)
		(mid 339.954616 -268.195193)
		(end 339.767418 -268.245336)
		(width 0.088646)
		(layer "In11.Cu")
		(net "M_D_CPU0_SA_DQS_DP<3>")
	)
	(arc
		(start 333.56296 -268.245336)
		(mid 333.390623 -268.195137)
		(end 333.214726 -268.230858)
		(width 0.088646)
		(layer "In11.Cu")
		(net "M_D_CPU0_SA_DQS_DP<3>")
	)
	(arc
		(start 336.947764 -268.245336)
		(mid 336.665062 -268.321112)
		(end 336.38236 -268.245336)
		(width 0.088646)
		(layer "In11.Cu")
		(net "M_D_CPU0_SA_DQS_DP<3>")
	)
	(arc
		(start 344.840814 -268.245336)
		(mid 344.653616 -268.195193)
		(end 344.466418 -268.245336)
		(width 0.088646)
		(layer "In11.Cu")
		(net "M_D_CPU0_SA_DQS_DP<3>")
	)
	(arc
		(start 339.767418 -268.245336)
		(mid 339.493219 -268.321171)
		(end 339.216746 -268.253972)
		(width 0.088646)
		(layer "In11.Cu")
		(net "M_D_CPU0_SA_DQS_DP<3>")
	)
	(arc
		(start 335.068164 -268.245336)
		(mid 334.785462 -268.321112)
		(end 334.50276 -268.245336)
		(width 0.088646)
		(layer "In11.Cu")
		(net "M_D_CPU0_SA_DQS_DP<3>")
	)
	(arc
		(start 332.65364 -268.264386)
		(mid 332.46804 -268.227178)
		(end 332.27899 -268.2367)
		(width 0.088646)
		(layer "In11.Cu")
		(net "M_D_CPU0_SA_DQS_DP<3>")
	)
	(arc
		(start 339.202014 -268.245336)
		(mid 339.014816 -268.195193)
		(end 338.827618 -268.245336)
		(width 0.088646)
		(layer "In11.Cu")
		(net "M_D_CPU0_SA_DQS_DP<3>")
	)
	(arc
		(start 342.021414 -268.245336)
		(mid 341.834216 -268.195193)
		(end 341.647018 -268.245336)
		(width 0.088646)
		(layer "In11.Cu")
		(net "M_D_CPU0_SA_DQS_DP<3>")
	)
	(arc
		(start 334.50276 -268.245336)
		(mid 334.315562 -268.195193)
		(end 334.128364 -268.245336)
		(width 0.088646)
		(layer "In11.Cu")
		(net "M_D_CPU0_SA_DQS_DP<3>")
	)
	(arc
		(start 332.27899 -268.2367)
		(mid 332.226478 -268.267069)
		(end 332.205838 -268.324076)
		(width 0.088646)
		(layer "In11.Cu")
		(net "M_D_CPU0_SA_DQS_DP<3>")
	)
	(arc
		(start 337.32216 -268.245336)
		(mid 337.134962 -268.195193)
		(end 336.947764 -268.245336)
		(width 0.088646)
		(layer "In11.Cu")
		(net "M_D_CPU0_SA_DQS_DP<3>")
	)
	(arc
		(start 342.586564 -268.245336)
		(mid 342.310005 -268.321079)
		(end 342.031828 -268.251432)
		(width 0.088646)
		(layer "In11.Cu")
		(net "M_D_CPU0_SA_DQS_DP<3>")
	)
	(arc
		(start 336.38236 -268.245336)
		(mid 336.195162 -268.195193)
		(end 336.007964 -268.245336)
		(width 0.088646)
		(layer "In11.Cu")
		(net "M_D_CPU0_SA_DQS_DP<3>")
	)
	(segment
		(start 258.567682 -294.380666)
		(end 257.940556 -294.380666)
		(width 0.20066)
		(layer "F.Cu")
		(net "M_D_CPU0_SA_DQS_DP<2>")
	)
	(segment
		(start 262.54583 -293.95547)
		(end 262.120634 -294.380666)
		(width 0.20066)
		(layer "F.Cu")
		(net "M_D_CPU0_SA_DQS_DP<2>")
	)
	(segment
		(start 264.729214 -294.216582)
		(end 263.624314 -294.216582)
		(width 0.20066)
		(layer "F.Cu")
		(net "M_D_CPU0_SA_DQS_DP<2>")
	)
	(segment
		(start 256.618486 -294.216582)
		(end 256.080514 -294.216582)
		(width 0.20066)
		(layer "F.Cu")
		(net "M_D_CPU0_SA_DQS_DP<2>")
	)
	(segment
		(start 257.30454 -293.95547)
		(end 256.879598 -293.95547)
		(width 0.20066)
		(layer "F.Cu")
		(net "M_D_CPU0_SA_DQS_DP<2>")
	)
	(segment
		(start 262.120634 -294.380666)
		(end 261.794752 -294.380666)
		(width 0.20066)
		(layer "F.Cu")
		(net "M_D_CPU0_SA_DQS_DP<2>")
	)
	(segment
		(start 259.056378 -294.651176)
		(end 258.838192 -294.651176)
		(width 0.20066)
		(layer "F.Cu")
		(net "M_D_CPU0_SA_DQS_DP<2>")
	)
	(segment
		(start 263.075674 -294.216582)
		(end 262.814562 -293.95547)
		(width 0.20066)
		(layer "F.Cu")
		(net "M_D_CPU0_SA_DQS_DP<2>")
	)
	(segment
		(start 262.814562 -293.95547)
		(end 262.54583 -293.95547)
		(width 0.20066)
		(layer "F.Cu")
		(net "M_D_CPU0_SA_DQS_DP<2>")
	)
	(segment
		(start 256.879598 -293.95547)
		(end 256.618486 -294.216582)
		(width 0.20066)
		(layer "F.Cu")
		(net "M_D_CPU0_SA_DQS_DP<2>")
	)
	(segment
		(start 261.058152 -294.641778)
		(end 259.302758 -294.641778)
		(width 0.1016)
		(layer "F.Cu")
		(net "M_D_CPU0_SA_DQS_DP<2>")
	)
	(segment
		(start 258.838192 -294.651176)
		(end 258.567682 -294.380666)
		(width 0.20066)
		(layer "F.Cu")
		(net "M_D_CPU0_SA_DQS_DP<2>")
	)
	(segment
		(start 257.940556 -294.380666)
		(end 257.30454 -293.95547)
		(width 0.20066)
		(layer "F.Cu")
		(net "M_D_CPU0_SA_DQS_DP<2>")
	)
	(segment
		(start 261.381494 -294.641778)
		(end 261.058152 -294.641778)
		(width 0.101854)
		(layer "F.Cu")
		(net "M_D_CPU0_SA_DQS_DP<2>")
	)
	(segment
		(start 261.794752 -294.380666)
		(end 261.53364 -294.641778)
		(width 0.20066)
		(layer "F.Cu")
		(net "M_D_CPU0_SA_DQS_DP<2>")
	)
	(segment
		(start 259.065776 -294.641778)
		(end 259.056378 -294.651176)
		(width 0.101854)
		(layer "F.Cu")
		(net "M_D_CPU0_SA_DQS_DP<2>")
	)
	(segment
		(start 259.302758 -294.641778)
		(end 259.065776 -294.641778)
		(width 0.101854)
		(layer "F.Cu")
		(net "M_D_CPU0_SA_DQS_DP<2>")
	)
	(segment
		(start 261.53364 -294.641778)
		(end 261.381494 -294.641778)
		(width 0.20066)
		(layer "F.Cu")
		(net "M_D_CPU0_SA_DQS_DP<2>")
	)
	(segment
		(start 263.624314 -294.216582)
		(end 263.075674 -294.216582)
		(width 0.20066)
		(layer "F.Cu")
		(net "M_D_CPU0_SA_DQS_DP<2>")
	)
	(arc
		(start 347.003116 -272.103342)
		(mid 347.003052 -272.371312)
		(end 347.002862 -272.639282)
		(width 0.20066)
		(layer "F.Cu")
		(net "M_D_CPU0_SA_DQS_DP<2>")
	)
	(segment
		(start 269.404846 -294.34409)
		(end 269.106142 -294.642794)
		(width 0.18288)
		(layer "In11.Cu")
		(net "M_D_CPU0_SA_DQS_DP<2>")
	)
	(segment
		(start 345.61526 -273.008344)
		(end 345.39174 -273.137122)
		(width 0.088646)
		(layer "In11.Cu")
		(net "M_D_CPU0_SA_DQS_DP<2>")
	)
	(segment
		(start 331.39126 -275.863304)
		(end 331.088238 -275.863304)
		(width 0.088646)
		(layer "In11.Cu")
		(net "M_D_CPU0_SA_DQS_DP<2>")
	)
	(segment
		(start 301.075852 -295.651428)
		(end 300.07687 -296.065194)
		(width 0.18288)
		(layer "In11.Cu")
		(net "M_D_CPU0_SA_DQS_DP<2>")
	)
	(segment
		(start 314.481972 -290.720526)
		(end 312.559192 -290.720526)
		(width 0.18288)
		(layer "In11.Cu")
		(net "M_D_CPU0_SA_DQS_DP<2>")
	)
	(segment
		(start 269.106142 -294.642794)
		(end 268.650212 -294.642794)
		(width 0.18288)
		(layer "In11.Cu")
		(net "M_D_CPU0_SA_DQS_DP<2>")
	)
	(segment
		(start 346.032836 -273.012662)
		(end 345.975686 -273.005804)
		(width 0.088646)
		(layer "In11.Cu")
		(net "M_D_CPU0_SA_DQS_DP<2>")
	)
	(segment
		(start 298.509182 -296.072052)
		(end 297.94708 -296.072052)
		(width 0.18288)
		(layer "In11.Cu")
		(net "M_D_CPU0_SA_DQS_DP<2>")
	)
	(segment
		(start 299.191934 -296.340784)
		(end 298.777914 -296.340784)
		(width 0.18288)
		(layer "In11.Cu")
		(net "M_D_CPU0_SA_DQS_DP<2>")
	)
	(segment
		(start 268.650212 -294.642794)
		(end 268.383004 -294.375586)
		(width 0.18288)
		(layer "In11.Cu")
		(net "M_D_CPU0_SA_DQS_DP<2>")
	)
	(segment
		(start 341.096346 -273.137376)
		(end 341.081614 -273.12874)
		(width 0.088646)
		(layer "In11.Cu")
		(net "M_D_CPU0_SA_DQS_DP<2>")
	)
	(segment
		(start 345.97086 -273.008344)
		(end 345.61526 -273.008344)
		(width 0.088646)
		(layer "In11.Cu")
		(net "M_D_CPU0_SA_DQS_DP<2>")
	)
	(segment
		(start 346.662502 -272.729198)
		(end 346.237306 -272.971006)
		(width 0.088646)
		(layer "In11.Cu")
		(net "M_D_CPU0_SA_DQS_DP<2>")
	)
	(segment
		(start 283.283914 -296.082212)
		(end 281.31897 -296.896282)
		(width 0.18288)
		(layer "In11.Cu")
		(net "M_D_CPU0_SA_DQS_DP<2>")
	)
	(segment
		(start 284.149038 -296.340784)
		(end 283.724858 -296.340784)
		(width 0.18288)
		(layer "In11.Cu")
		(net "M_D_CPU0_SA_DQS_DP<2>")
	)
	(segment
		(start 312.559192 -290.720526)
		(end 310.525414 -291.561774)
		(width 0.18288)
		(layer "In11.Cu")
		(net "M_D_CPU0_SA_DQS_DP<2>")
	)
	(segment
		(start 331.922628 -275.331936)
		(end 331.39126 -275.863304)
		(width 0.088646)
		(layer "In11.Cu")
		(net "M_D_CPU0_SA_DQS_DP<2>")
	)
	(segment
		(start 265.406886 -293.94277)
		(end 265.003026 -293.94277)
		(width 0.18288)
		(layer "In11.Cu")
		(net "M_D_CPU0_SA_DQS_DP<2>")
	)
	(segment
		(start 301.530004 -295.197276)
		(end 301.075852 -295.651428)
		(width 0.18288)
		(layer "In11.Cu")
		(net "M_D_CPU0_SA_DQS_DP<2>")
	)
	(segment
		(start 332.799182 -273.763486)
		(end 331.922628 -274.64004)
		(width 0.088646)
		(layer "In11.Cu")
		(net "M_D_CPU0_SA_DQS_DP<2>")
	)
	(segment
		(start 293.928546 -296.933366)
		(end 293.536116 -296.540936)
		(width 0.18288)
		(layer "In11.Cu")
		(net "M_D_CPU0_SA_DQS_DP<2>")
	)
	(segment
		(start 333.577946 -273.137376)
		(end 333.563214 -273.12874)
		(width 0.088646)
		(layer "In11.Cu")
		(net "M_D_CPU0_SA_DQS_DP<2>")
	)
	(segment
		(start 288.256726 -295.346628)
		(end 287.827212 -295.776142)
		(width 0.18288)
		(layer "In11.Cu")
		(net "M_D_CPU0_SA_DQS_DP<2>")
	)
	(segment
		(start 292.780466 -296.2275)
		(end 292.418262 -296.2275)
		(width 0.18288)
		(layer "In11.Cu")
		(net "M_D_CPU0_SA_DQS_DP<2>")
	)
	(segment
		(start 333.11084 -273.187922)
		(end 332.799182 -273.49958)
		(width 0.088646)
		(layer "In11.Cu")
		(net "M_D_CPU0_SA_DQS_DP<2>")
	)
	(segment
		(start 275.217382 -295.925748)
		(end 274.23364 -295.268396)
		(width 0.18288)
		(layer "In11.Cu")
		(net "M_D_CPU0_SA_DQS_DP<2>")
	)
	(segment
		(start 338.827618 -273.12874)
		(end 338.817204 -273.134836)
		(width 0.088646)
		(layer "In11.Cu")
		(net "M_D_CPU0_SA_DQS_DP<2>")
	)
	(segment
		(start 295.094406 -297.190922)
		(end 294.677846 -297.190922)
		(width 0.18288)
		(layer "In11.Cu")
		(net "M_D_CPU0_SA_DQS_DP<2>")
	)
	(segment
		(start 289.614102 -295.346628)
		(end 288.256726 -295.346628)
		(width 0.18288)
		(layer "In11.Cu")
		(net "M_D_CPU0_SA_DQS_DP<2>")
	)
	(segment
		(start 307.068982 -292.420548)
		(end 303.42459 -293.931086)
		(width 0.18288)
		(layer "In11.Cu")
		(net "M_D_CPU0_SA_DQS_DP<2>")
	)
	(segment
		(start 280.373582 -296.896282)
		(end 280.078942 -297.190922)
		(width 0.18288)
		(layer "In11.Cu")
		(net "M_D_CPU0_SA_DQS_DP<2>")
	)
	(segment
		(start 291.07384 -296.806366)
		(end 289.614102 -295.346628)
		(width 0.18288)
		(layer "In11.Cu")
		(net "M_D_CPU0_SA_DQS_DP<2>")
	)
	(segment
		(start 314.944252 -290.258246)
		(end 314.481972 -290.720526)
		(width 0.18288)
		(layer "In11.Cu")
		(net "M_D_CPU0_SA_DQS_DP<2>")
	)
	(segment
		(start 297.583098 -296.222928)
		(end 297.22318 -296.582846)
		(width 0.18288)
		(layer "In11.Cu")
		(net "M_D_CPU0_SA_DQS_DP<2>")
	)
	(segment
		(start 279.34158 -296.942256)
		(end 279.007824 -296.942256)
		(width 0.18288)
		(layer "In11.Cu")
		(net "M_D_CPU0_SA_DQS_DP<2>")
	)
	(segment
		(start 343.915746 -273.137376)
		(end 343.901014 -273.12874)
		(width 0.088646)
		(layer "In11.Cu")
		(net "M_D_CPU0_SA_DQS_DP<2>")
	)
	(segment
		(start 284.409388 -296.080434)
		(end 284.149038 -296.340784)
		(width 0.18288)
		(layer "In11.Cu")
		(net "M_D_CPU0_SA_DQS_DP<2>")
	)
	(segment
		(start 300.07687 -296.065194)
		(end 299.467524 -296.065194)
		(width 0.18288)
		(layer "In11.Cu")
		(net "M_D_CPU0_SA_DQS_DP<2>")
	)
	(segment
		(start 335.068164 -273.12874)
		(end 335.05775 -273.134836)
		(width 0.088646)
		(layer "In11.Cu")
		(net "M_D_CPU0_SA_DQS_DP<2>")
	)
	(segment
		(start 274.23364 -295.268396)
		(end 272.000472 -294.34409)
		(width 0.18288)
		(layer "In11.Cu")
		(net "M_D_CPU0_SA_DQS_DP<2>")
	)
	(segment
		(start 295.369234 -296.916094)
		(end 295.094406 -297.190922)
		(width 0.18288)
		(layer "In11.Cu")
		(net "M_D_CPU0_SA_DQS_DP<2>")
	)
	(segment
		(start 267.302742 -293.955978)
		(end 266.682474 -293.699184)
		(width 0.18288)
		(layer "In11.Cu")
		(net "M_D_CPU0_SA_DQS_DP<2>")
	)
	(segment
		(start 279.590246 -297.190922)
		(end 279.34158 -296.942256)
		(width 0.18288)
		(layer "In11.Cu")
		(net "M_D_CPU0_SA_DQS_DP<2>")
	)
	(segment
		(start 265.003026 -293.94277)
		(end 264.729214 -294.216582)
		(width 0.18288)
		(layer "In11.Cu")
		(net "M_D_CPU0_SA_DQS_DP<2>")
	)
	(segment
		(start 277.776178 -297.510454)
		(end 277.266908 -297.510454)
		(width 0.18288)
		(layer "In11.Cu")
		(net "M_D_CPU0_SA_DQS_DP<2>")
	)
	(segment
		(start 280.078942 -297.190922)
		(end 279.590246 -297.190922)
		(width 0.18288)
		(layer "In11.Cu")
		(net "M_D_CPU0_SA_DQS_DP<2>")
	)
	(segment
		(start 310.525414 -291.561774)
		(end 307.927756 -291.561774)
		(width 0.18288)
		(layer "In11.Cu")
		(net "M_D_CPU0_SA_DQS_DP<2>")
	)
	(segment
		(start 291.839396 -296.806366)
		(end 291.07384 -296.806366)
		(width 0.18288)
		(layer "In11.Cu")
		(net "M_D_CPU0_SA_DQS_DP<2>")
	)
	(segment
		(start 267.722604 -294.375586)
		(end 267.302742 -293.955978)
		(width 0.18288)
		(layer "In11.Cu")
		(net "M_D_CPU0_SA_DQS_DP<2>")
	)
	(segment
		(start 297.94708 -296.072052)
		(end 297.583098 -296.222928)
		(width 0.18288)
		(layer "In11.Cu")
		(net "M_D_CPU0_SA_DQS_DP<2>")
	)
	(segment
		(start 345.975686 -273.005804)
		(end 345.97086 -273.008344)
		(width 0.088646)
		(layer "In11.Cu")
		(net "M_D_CPU0_SA_DQS_DP<2>")
	)
	(segment
		(start 296.418254 -296.916094)
		(end 295.369234 -296.916094)
		(width 0.18288)
		(layer "In11.Cu")
		(net "M_D_CPU0_SA_DQS_DP<2>")
	)
	(segment
		(start 294.42029 -296.933366)
		(end 293.928546 -296.933366)
		(width 0.18288)
		(layer "In11.Cu")
		(net "M_D_CPU0_SA_DQS_DP<2>")
	)
	(segment
		(start 344.84056 -273.12874)
		(end 344.840814 -273.12874)
		(width 0.088646)
		(layer "In11.Cu")
		(net "M_D_CPU0_SA_DQS_DP<2>")
	)
	(segment
		(start 283.466286 -296.082212)
		(end 283.283914 -296.082212)
		(width 0.18288)
		(layer "In11.Cu")
		(net "M_D_CPU0_SA_DQS_DP<2>")
	)
	(segment
		(start 292.418262 -296.2275)
		(end 291.839396 -296.806366)
		(width 0.18288)
		(layer "In11.Cu")
		(net "M_D_CPU0_SA_DQS_DP<2>")
	)
	(segment
		(start 297.22318 -296.582846)
		(end 296.418254 -296.916094)
		(width 0.18288)
		(layer "In11.Cu")
		(net "M_D_CPU0_SA_DQS_DP<2>")
	)
	(segment
		(start 294.677846 -297.190922)
		(end 294.42029 -296.933366)
		(width 0.18288)
		(layer "In11.Cu")
		(net "M_D_CPU0_SA_DQS_DP<2>")
	)
	(segment
		(start 279.007824 -296.942256)
		(end 277.776178 -297.510454)
		(width 0.18288)
		(layer "In11.Cu")
		(net "M_D_CPU0_SA_DQS_DP<2>")
	)
	(segment
		(start 298.777914 -296.340784)
		(end 298.509182 -296.072052)
		(width 0.18288)
		(layer "In11.Cu")
		(net "M_D_CPU0_SA_DQS_DP<2>")
	)
	(segment
		(start 336.947764 -273.12874)
		(end 336.933032 -273.137376)
		(width 0.088646)
		(layer "In11.Cu")
		(net "M_D_CPU0_SA_DQS_DP<2>")
	)
	(segment
		(start 293.536116 -296.540936)
		(end 292.780466 -296.2275)
		(width 0.18288)
		(layer "In11.Cu")
		(net "M_D_CPU0_SA_DQS_DP<2>")
	)
	(segment
		(start 268.383004 -294.375586)
		(end 267.722604 -294.375586)
		(width 0.18288)
		(layer "In11.Cu")
		(net "M_D_CPU0_SA_DQS_DP<2>")
	)
	(segment
		(start 314.944252 -289.761168)
		(end 314.944252 -290.258246)
		(width 0.18288)
		(layer "In11.Cu")
		(net "M_D_CPU0_SA_DQS_DP<2>")
	)
	(segment
		(start 328.782172 -275.923248)
		(end 314.944252 -289.761168)
		(width 0.18288)
		(layer "In11.Cu")
		(net "M_D_CPU0_SA_DQS_DP<2>")
	)
	(segment
		(start 277.266908 -297.510454)
		(end 276.473666 -297.182286)
		(width 0.18288)
		(layer "In11.Cu")
		(net "M_D_CPU0_SA_DQS_DP<2>")
	)
	(segment
		(start 281.31897 -296.896282)
		(end 280.373582 -296.896282)
		(width 0.18288)
		(layer "In11.Cu")
		(net "M_D_CPU0_SA_DQS_DP<2>")
	)
	(segment
		(start 272.000472 -294.34409)
		(end 269.404846 -294.34409)
		(width 0.18288)
		(layer "In11.Cu")
		(net "M_D_CPU0_SA_DQS_DP<2>")
	)
	(segment
		(start 342.971374 -273.134836)
		(end 342.96096 -273.12874)
		(width 0.088646)
		(layer "In11.Cu")
		(net "M_D_CPU0_SA_DQS_DP<2>")
	)
	(segment
		(start 287.092644 -296.080434)
		(end 284.409388 -296.080434)
		(width 0.18288)
		(layer "In11.Cu")
		(net "M_D_CPU0_SA_DQS_DP<2>")
	)
	(segment
		(start 276.473666 -297.182286)
		(end 275.217382 -295.925748)
		(width 0.18288)
		(layer "In11.Cu")
		(net "M_D_CPU0_SA_DQS_DP<2>")
	)
	(segment
		(start 342.031828 -273.134836)
		(end 342.021414 -273.12874)
		(width 0.088646)
		(layer "In11.Cu")
		(net "M_D_CPU0_SA_DQS_DP<2>")
	)
	(segment
		(start 332.799182 -273.49958)
		(end 332.799182 -273.763486)
		(width 0.088646)
		(layer "In11.Cu")
		(net "M_D_CPU0_SA_DQS_DP<2>")
	)
	(segment
		(start 266.682474 -293.699184)
		(end 265.994896 -293.699184)
		(width 0.18288)
		(layer "In11.Cu")
		(net "M_D_CPU0_SA_DQS_DP<2>")
	)
	(segment
		(start 287.827212 -295.776142)
		(end 287.092644 -296.080434)
		(width 0.18288)
		(layer "In11.Cu")
		(net "M_D_CPU0_SA_DQS_DP<2>")
	)
	(segment
		(start 283.724858 -296.340784)
		(end 283.466286 -296.082212)
		(width 0.18288)
		(layer "In11.Cu")
		(net "M_D_CPU0_SA_DQS_DP<2>")
	)
	(segment
		(start 265.994896 -293.699184)
		(end 265.406886 -293.94277)
		(width 0.18288)
		(layer "In11.Cu")
		(net "M_D_CPU0_SA_DQS_DP<2>")
	)
	(segment
		(start 303.42459 -293.931086)
		(end 301.530004 -295.197276)
		(width 0.18288)
		(layer "In11.Cu")
		(net "M_D_CPU0_SA_DQS_DP<2>")
	)
	(segment
		(start 339.216746 -273.137376)
		(end 339.202014 -273.12874)
		(width 0.088646)
		(layer "In11.Cu")
		(net "M_D_CPU0_SA_DQS_DP<2>")
	)
	(segment
		(start 331.922628 -274.64004)
		(end 331.922628 -275.331936)
		(width 0.088646)
		(layer "In11.Cu")
		(net "M_D_CPU0_SA_DQS_DP<2>")
	)
	(segment
		(start 299.467524 -296.065194)
		(end 299.191934 -296.340784)
		(width 0.18288)
		(layer "In11.Cu")
		(net "M_D_CPU0_SA_DQS_DP<2>")
	)
	(segment
		(start 331.028294 -275.923248)
		(end 328.782172 -275.923248)
		(width 0.18288)
		(layer "In11.Cu")
		(net "M_D_CPU0_SA_DQS_DP<2>")
	)
	(segment
		(start 340.156546 -273.137376)
		(end 340.141814 -273.12874)
		(width 0.088646)
		(layer "In11.Cu")
		(net "M_D_CPU0_SA_DQS_DP<2>")
	)
	(segment
		(start 331.088238 -275.863304)
		(end 331.028294 -275.923248)
		(width 0.088646)
		(layer "In11.Cu")
		(net "M_D_CPU0_SA_DQS_DP<2>")
	)
	(segment
		(start 307.927756 -291.561774)
		(end 307.068982 -292.420548)
		(width 0.18288)
		(layer "In11.Cu")
		(net "M_D_CPU0_SA_DQS_DP<2>")
	)
	(arc
		(start 341.647018 -273.12874)
		(mid 341.372819 -273.204575)
		(end 341.096346 -273.137376)
		(width 0.088646)
		(layer "In11.Cu")
		(net "M_D_CPU0_SA_DQS_DP<2>")
	)
	(arc
		(start 336.933032 -273.137376)
		(mid 336.656557 -273.204696)
		(end 336.38236 -273.12874)
		(width 0.088646)
		(layer "In11.Cu")
		(net "M_D_CPU0_SA_DQS_DP<2>")
	)
	(arc
		(start 333.132684 -273.167856)
		(mid 333.121563 -273.177672)
		(end 333.11084 -273.187922)
		(width 0.088646)
		(layer "In11.Cu")
		(net "M_D_CPU0_SA_DQS_DP<2>")
	)
	(arc
		(start 335.44256 -273.12874)
		(mid 335.255362 -273.078597)
		(end 335.068164 -273.12874)
		(width 0.088646)
		(layer "In11.Cu")
		(net "M_D_CPU0_SA_DQS_DP<2>")
	)
	(arc
		(start 340.141814 -273.12874)
		(mid 339.954616 -273.078597)
		(end 339.767418 -273.12874)
		(width 0.088646)
		(layer "In11.Cu")
		(net "M_D_CPU0_SA_DQS_DP<2>")
	)
	(arc
		(start 344.466418 -273.12874)
		(mid 344.192219 -273.204575)
		(end 343.915746 -273.137376)
		(width 0.088646)
		(layer "In11.Cu")
		(net "M_D_CPU0_SA_DQS_DP<2>")
	)
	(arc
		(start 339.767418 -273.12874)
		(mid 339.493219 -273.204575)
		(end 339.216746 -273.137376)
		(width 0.088646)
		(layer "In11.Cu")
		(net "M_D_CPU0_SA_DQS_DP<2>")
	)
	(arc
		(start 342.021414 -273.12874)
		(mid 341.834216 -273.078597)
		(end 341.647018 -273.12874)
		(width 0.088646)
		(layer "In11.Cu")
		(net "M_D_CPU0_SA_DQS_DP<2>")
	)
	(arc
		(start 341.081614 -273.12874)
		(mid 340.894416 -273.078597)
		(end 340.707218 -273.12874)
		(width 0.088646)
		(layer "In11.Cu")
		(net "M_D_CPU0_SA_DQS_DP<2>")
	)
	(arc
		(start 337.32216 -273.12874)
		(mid 337.134962 -273.078597)
		(end 336.947764 -273.12874)
		(width 0.088646)
		(layer "In11.Cu")
		(net "M_D_CPU0_SA_DQS_DP<2>")
	)
	(arc
		(start 345.39174 -273.137122)
		(mid 345.115075 -273.204593)
		(end 344.84056 -273.12874)
		(width 0.088646)
		(layer "In11.Cu")
		(net "M_D_CPU0_SA_DQS_DP<2>")
	)
	(arc
		(start 337.887564 -273.12874)
		(mid 337.604862 -273.204516)
		(end 337.32216 -273.12874)
		(width 0.088646)
		(layer "In11.Cu")
		(net "M_D_CPU0_SA_DQS_DP<2>")
	)
	(arc
		(start 336.38236 -273.12874)
		(mid 336.195162 -273.078597)
		(end 336.007964 -273.12874)
		(width 0.088646)
		(layer "In11.Cu")
		(net "M_D_CPU0_SA_DQS_DP<2>")
	)
	(arc
		(start 342.96096 -273.12874)
		(mid 342.773762 -273.078597)
		(end 342.586564 -273.12874)
		(width 0.088646)
		(layer "In11.Cu")
		(net "M_D_CPU0_SA_DQS_DP<2>")
	)
	(arc
		(start 333.188818 -273.12874)
		(mid 333.159858 -273.147017)
		(end 333.132684 -273.167856)
		(width 0.088646)
		(layer "In11.Cu")
		(net "M_D_CPU0_SA_DQS_DP<2>")
	)
	(arc
		(start 347.002862 -272.639282)
		(mid 346.826841 -272.662119)
		(end 346.662502 -272.729198)
		(width 0.088646)
		(layer "In11.Cu")
		(net "M_D_CPU0_SA_DQS_DP<2>")
	)
	(arc
		(start 342.586564 -273.12874)
		(mid 342.310005 -273.204483)
		(end 342.031828 -273.134836)
		(width 0.088646)
		(layer "In11.Cu")
		(net "M_D_CPU0_SA_DQS_DP<2>")
	)
	(arc
		(start 335.05775 -273.134836)
		(mid 334.779572 -273.204559)
		(end 334.503014 -273.12874)
		(width 0.088646)
		(layer "In11.Cu")
		(net "M_D_CPU0_SA_DQS_DP<2>")
	)
	(arc
		(start 344.840814 -273.12874)
		(mid 344.653616 -273.078597)
		(end 344.466418 -273.12874)
		(width 0.088646)
		(layer "In11.Cu")
		(net "M_D_CPU0_SA_DQS_DP<2>")
	)
	(arc
		(start 334.128618 -273.12874)
		(mid 333.854419 -273.204575)
		(end 333.577946 -273.137376)
		(width 0.088646)
		(layer "In11.Cu")
		(net "M_D_CPU0_SA_DQS_DP<2>")
	)
	(arc
		(start 339.202014 -273.12874)
		(mid 339.014816 -273.078597)
		(end 338.827618 -273.12874)
		(width 0.088646)
		(layer "In11.Cu")
		(net "M_D_CPU0_SA_DQS_DP<2>")
	)
	(arc
		(start 334.503014 -273.12874)
		(mid 334.315816 -273.078597)
		(end 334.128618 -273.12874)
		(width 0.088646)
		(layer "In11.Cu")
		(net "M_D_CPU0_SA_DQS_DP<2>")
	)
	(arc
		(start 333.563214 -273.12874)
		(mid 333.376016 -273.078597)
		(end 333.188818 -273.12874)
		(width 0.088646)
		(layer "In11.Cu")
		(net "M_D_CPU0_SA_DQS_DP<2>")
	)
	(arc
		(start 346.237306 -272.971006)
		(mid 346.138464 -273.008516)
		(end 346.032836 -273.012662)
		(width 0.088646)
		(layer "In11.Cu")
		(net "M_D_CPU0_SA_DQS_DP<2>")
	)
	(arc
		(start 343.901014 -273.12874)
		(mid 343.713816 -273.078597)
		(end 343.526618 -273.12874)
		(width 0.088646)
		(layer "In11.Cu")
		(net "M_D_CPU0_SA_DQS_DP<2>")
	)
	(arc
		(start 338.26196 -273.12874)
		(mid 338.074762 -273.078597)
		(end 337.887564 -273.12874)
		(width 0.088646)
		(layer "In11.Cu")
		(net "M_D_CPU0_SA_DQS_DP<2>")
	)
	(arc
		(start 338.817204 -273.134836)
		(mid 338.538772 -273.204682)
		(end 338.26196 -273.12874)
		(width 0.088646)
		(layer "In11.Cu")
		(net "M_D_CPU0_SA_DQS_DP<2>")
	)
	(arc
		(start 343.526618 -273.12874)
		(mid 343.249805 -273.20461)
		(end 342.971374 -273.134836)
		(width 0.088646)
		(layer "In11.Cu")
		(net "M_D_CPU0_SA_DQS_DP<2>")
	)
	(arc
		(start 336.007964 -273.12874)
		(mid 335.725262 -273.204516)
		(end 335.44256 -273.12874)
		(width 0.088646)
		(layer "In11.Cu")
		(net "M_D_CPU0_SA_DQS_DP<2>")
	)
	(arc
		(start 340.707218 -273.12874)
		(mid 340.433019 -273.204575)
		(end 340.156546 -273.137376)
		(width 0.088646)
		(layer "In11.Cu")
		(net "M_D_CPU0_SA_DQS_DP<2>")
	)
	(segment
		(start 263.075674 -303.566576)
		(end 262.814562 -303.305464)
		(width 0.20066)
		(layer "F.Cu")
		(net "M_D_CPU0_SA_DQS_DP<1>")
	)
	(segment
		(start 264.729214 -303.566576)
		(end 263.624314 -303.566576)
		(width 0.20066)
		(layer "F.Cu")
		(net "M_D_CPU0_SA_DQS_DP<1>")
	)
	(segment
		(start 256.618486 -303.566576)
		(end 256.080514 -303.566576)
		(width 0.20066)
		(layer "F.Cu")
		(net "M_D_CPU0_SA_DQS_DP<1>")
	)
	(segment
		(start 261.794752 -303.73066)
		(end 261.53364 -303.991772)
		(width 0.20066)
		(layer "F.Cu")
		(net "M_D_CPU0_SA_DQS_DP<1>")
	)
	(segment
		(start 257.30454 -303.305464)
		(end 256.879598 -303.305464)
		(width 0.20066)
		(layer "F.Cu")
		(net "M_D_CPU0_SA_DQS_DP<1>")
	)
	(segment
		(start 259.065776 -303.991772)
		(end 259.056378 -304.00117)
		(width 0.101854)
		(layer "F.Cu")
		(net "M_D_CPU0_SA_DQS_DP<1>")
	)
	(segment
		(start 256.879598 -303.305464)
		(end 256.618486 -303.566576)
		(width 0.20066)
		(layer "F.Cu")
		(net "M_D_CPU0_SA_DQS_DP<1>")
	)
	(segment
		(start 257.940556 -303.73066)
		(end 257.30454 -303.305464)
		(width 0.20066)
		(layer "F.Cu")
		(net "M_D_CPU0_SA_DQS_DP<1>")
	)
	(segment
		(start 259.056378 -304.00117)
		(end 258.838192 -304.00117)
		(width 0.20066)
		(layer "F.Cu")
		(net "M_D_CPU0_SA_DQS_DP<1>")
	)
	(segment
		(start 261.53364 -303.991772)
		(end 261.381494 -303.991772)
		(width 0.20066)
		(layer "F.Cu")
		(net "M_D_CPU0_SA_DQS_DP<1>")
	)
	(segment
		(start 259.302758 -303.991772)
		(end 259.065776 -303.991772)
		(width 0.101854)
		(layer "F.Cu")
		(net "M_D_CPU0_SA_DQS_DP<1>")
	)
	(segment
		(start 258.838192 -304.00117)
		(end 258.567682 -303.73066)
		(width 0.20066)
		(layer "F.Cu")
		(net "M_D_CPU0_SA_DQS_DP<1>")
	)
	(segment
		(start 258.567682 -303.73066)
		(end 257.940556 -303.73066)
		(width 0.20066)
		(layer "F.Cu")
		(net "M_D_CPU0_SA_DQS_DP<1>")
	)
	(segment
		(start 262.814562 -303.305464)
		(end 262.54583 -303.305464)
		(width 0.20066)
		(layer "F.Cu")
		(net "M_D_CPU0_SA_DQS_DP<1>")
	)
	(segment
		(start 261.058152 -303.991772)
		(end 259.302758 -303.991772)
		(width 0.1016)
		(layer "F.Cu")
		(net "M_D_CPU0_SA_DQS_DP<1>")
	)
	(segment
		(start 261.381494 -303.991772)
		(end 261.058152 -303.991772)
		(width 0.101854)
		(layer "F.Cu")
		(net "M_D_CPU0_SA_DQS_DP<1>")
	)
	(segment
		(start 263.624314 -303.566576)
		(end 263.075674 -303.566576)
		(width 0.20066)
		(layer "F.Cu")
		(net "M_D_CPU0_SA_DQS_DP<1>")
	)
	(segment
		(start 262.54583 -303.305464)
		(end 262.120634 -303.73066)
		(width 0.20066)
		(layer "F.Cu")
		(net "M_D_CPU0_SA_DQS_DP<1>")
	)
	(segment
		(start 262.120634 -303.73066)
		(end 261.794752 -303.73066)
		(width 0.20066)
		(layer "F.Cu")
		(net "M_D_CPU0_SA_DQS_DP<1>")
	)
	(arc
		(start 347.003116 -276.986492)
		(mid 347.003052 -277.254462)
		(end 347.002862 -277.522432)
		(width 0.20066)
		(layer "F.Cu")
		(net "M_D_CPU0_SA_DQS_DP<1>")
	)
	(segment
		(start 278.42972 -310.077104)
		(end 277.98649 -310.260746)
		(width 0.18288)
		(layer "In11.Cu")
		(net "M_D_CPU0_SA_DQS_DP<1>")
	)
	(segment
		(start 294.677846 -309.94096)
		(end 294.435276 -309.69839)
		(width 0.18288)
		(layer "In11.Cu")
		(net "M_D_CPU0_SA_DQS_DP<1>")
	)
	(segment
		(start 342.036146 -278.02078)
		(end 342.021414 -278.012144)
		(width 0.088646)
		(layer "In11.Cu")
		(net "M_D_CPU0_SA_DQS_DP<1>")
	)
	(segment
		(start 313.874658 -301.440088)
		(end 313.594242 -301.159672)
		(width 0.18288)
		(layer "In11.Cu")
		(net "M_D_CPU0_SA_DQS_DP<1>")
	)
	(segment
		(start 267.940282 -303.684432)
		(end 267.663676 -303.961038)
		(width 0.18288)
		(layer "In11.Cu")
		(net "M_D_CPU0_SA_DQS_DP<1>")
	)
	(segment
		(start 280.001218 -309.94096)
		(end 279.62479 -309.94096)
		(width 0.18288)
		(layer "In11.Cu")
		(net "M_D_CPU0_SA_DQS_DP<1>")
	)
	(segment
		(start 346.662502 -277.612348)
		(end 346.237306 -277.854156)
		(width 0.088646)
		(layer "In11.Cu")
		(net "M_D_CPU0_SA_DQS_DP<1>")
	)
	(segment
		(start 338.827618 -278.01189)
		(end 338.827364 -278.012144)
		(width 0.088646)
		(layer "In11.Cu")
		(net "M_D_CPU0_SA_DQS_DP<1>")
	)
	(segment
		(start 331.756512 -282.334462)
		(end 330.929996 -282.334462)
		(width 0.18288)
		(layer "In11.Cu")
		(net "M_D_CPU0_SA_DQS_DP<1>")
	)
	(segment
		(start 336.007964 -278.012144)
		(end 335.999074 -278.017224)
		(width 0.088646)
		(layer "In11.Cu")
		(net "M_D_CPU0_SA_DQS_DP<1>")
	)
	(segment
		(start 276.21357 -309.762398)
		(end 275.22551 -308.77383)
		(width 0.18288)
		(layer "In11.Cu")
		(net "M_D_CPU0_SA_DQS_DP<1>")
	)
	(segment
		(start 281.21483 -309.677562)
		(end 280.264616 -309.677562)
		(width 0.18288)
		(layer "In11.Cu")
		(net "M_D_CPU0_SA_DQS_DP<1>")
	)
	(segment
		(start 269.296896 -303.71034)
		(end 269.014448 -303.992788)
		(width 0.18288)
		(layer "In11.Cu")
		(net "M_D_CPU0_SA_DQS_DP<1>")
	)
	(segment
		(start 345.61526 -277.891494)
		(end 345.39174 -278.020272)
		(width 0.088646)
		(layer "In11.Cu")
		(net "M_D_CPU0_SA_DQS_DP<1>")
	)
	(segment
		(start 298.48302 -308.822852)
		(end 296.430192 -309.673498)
		(width 0.18288)
		(layer "In11.Cu")
		(net "M_D_CPU0_SA_DQS_DP<1>")
	)
	(segment
		(start 269.92834 -303.762156)
		(end 269.92834 -303.761902)
		(width 0.18288)
		(layer "In11.Cu")
		(net "M_D_CPU0_SA_DQS_DP<1>")
	)
	(segment
		(start 272.293334 -305.460654)
		(end 271.93621 -305.10353)
		(width 0.18288)
		(layer "In11.Cu")
		(net "M_D_CPU0_SA_DQS_DP<1>")
	)
	(segment
		(start 315.093858 -301.141892)
		(end 314.597034 -301.141892)
		(width 0.18288)
		(layer "In11.Cu")
		(net "M_D_CPU0_SA_DQS_DP<1>")
	)
	(segment
		(start 314.597034 -301.141892)
		(end 314.298838 -301.440088)
		(width 0.18288)
		(layer "In11.Cu")
		(net "M_D_CPU0_SA_DQS_DP<1>")
	)
	(segment
		(start 317.351664 -296.628058)
		(end 317.351664 -298.884086)
		(width 0.18288)
		(layer "In11.Cu")
		(net "M_D_CPU0_SA_DQS_DP<1>")
	)
	(segment
		(start 279.62479 -309.94096)
		(end 279.36444 -309.68061)
		(width 0.18288)
		(layer "In11.Cu")
		(net "M_D_CPU0_SA_DQS_DP<1>")
	)
	(segment
		(start 284.373828 -308.827424)
		(end 284.11043 -309.090822)
		(width 0.18288)
		(layer "In11.Cu")
		(net "M_D_CPU0_SA_DQS_DP<1>")
	)
	(segment
		(start 346.032836 -277.895812)
		(end 345.975686 -277.888954)
		(width 0.088646)
		(layer "In11.Cu")
		(net "M_D_CPU0_SA_DQS_DP<1>")
	)
	(segment
		(start 306.36845 -303.03724)
		(end 306.011834 -303.393856)
		(width 0.18288)
		(layer "In11.Cu")
		(net "M_D_CPU0_SA_DQS_DP<1>")
	)
	(segment
		(start 309.538116 -302.063404)
		(end 308.794912 -302.063404)
		(width 0.18288)
		(layer "In11.Cu")
		(net "M_D_CPU0_SA_DQS_DP<1>")
	)
	(segment
		(start 265.271504 -303.28616)
		(end 265.00963 -303.28616)
		(width 0.18288)
		(layer "In11.Cu")
		(net "M_D_CPU0_SA_DQS_DP<1>")
	)
	(segment
		(start 295.372028 -309.673498)
		(end 295.104566 -309.94096)
		(width 0.18288)
		(layer "In11.Cu")
		(net "M_D_CPU0_SA_DQS_DP<1>")
	)
	(segment
		(start 299.21835 -309.090822)
		(end 298.811442 -309.090822)
		(width 0.18288)
		(layer "In11.Cu")
		(net "M_D_CPU0_SA_DQS_DP<1>")
	)
	(segment
		(start 274.160996 -306.234084)
		(end 272.293334 -305.4604)
		(width 0.18288)
		(layer "In11.Cu")
		(net "M_D_CPU0_SA_DQS_DP<1>")
	)
	(segment
		(start 266.19073 -304.205386)
		(end 265.271504 -303.28616)
		(width 0.18288)
		(layer "In11.Cu")
		(net "M_D_CPU0_SA_DQS_DP<1>")
	)
	(segment
		(start 304.234342 -306.464462)
		(end 301.557182 -307.573426)
		(width 0.18288)
		(layer "In11.Cu")
		(net "M_D_CPU0_SA_DQS_DP<1>")
	)
	(segment
		(start 298.811442 -309.090822)
		(end 298.543472 -308.822852)
		(width 0.18288)
		(layer "In11.Cu")
		(net "M_D_CPU0_SA_DQS_DP<1>")
	)
	(segment
		(start 283.327602 -308.802532)
		(end 281.21483 -309.677562)
		(width 0.18288)
		(layer "In11.Cu")
		(net "M_D_CPU0_SA_DQS_DP<1>")
	)
	(segment
		(start 269.928594 -303.762156)
		(end 269.92834 -303.762156)
		(width 0.18288)
		(layer "In11.Cu")
		(net "M_D_CPU0_SA_DQS_DP<1>")
	)
	(segment
		(start 308.246018 -302.612552)
		(end 307.220874 -303.03724)
		(width 0.18288)
		(layer "In11.Cu")
		(net "M_D_CPU0_SA_DQS_DP<1>")
	)
	(segment
		(start 332.295246 -281.710892)
		(end 332.295246 -281.795728)
		(width 0.088646)
		(layer "In11.Cu")
		(net "M_D_CPU0_SA_DQS_DP<1>")
	)
	(segment
		(start 299.477684 -308.831488)
		(end 299.21835 -309.090822)
		(width 0.18288)
		(layer "In11.Cu")
		(net "M_D_CPU0_SA_DQS_DP<1>")
	)
	(segment
		(start 343.915746 -278.02078)
		(end 343.901014 -278.012144)
		(width 0.088646)
		(layer "In11.Cu")
		(net "M_D_CPU0_SA_DQS_DP<1>")
	)
	(segment
		(start 292.483794 -309.082694)
		(end 292.128194 -309.230014)
		(width 0.18288)
		(layer "In11.Cu")
		(net "M_D_CPU0_SA_DQS_DP<1>")
	)
	(segment
		(start 310.254142 -302.290734)
		(end 309.765446 -302.290734)
		(width 0.18288)
		(layer "In11.Cu")
		(net "M_D_CPU0_SA_DQS_DP<1>")
	)
	(segment
		(start 298.543472 -308.822852)
		(end 298.48302 -308.822852)
		(width 0.18288)
		(layer "In11.Cu")
		(net "M_D_CPU0_SA_DQS_DP<1>")
	)
	(segment
		(start 311.591452 -302.034702)
		(end 310.510174 -302.034702)
		(width 0.18288)
		(layer "In11.Cu")
		(net "M_D_CPU0_SA_DQS_DP<1>")
	)
	(segment
		(start 274.6756 -307.447442)
		(end 274.6756 -306.915566)
		(width 0.18288)
		(layer "In11.Cu")
		(net "M_D_CPU0_SA_DQS_DP<1>")
	)
	(segment
		(start 291.845492 -309.512716)
		(end 289.249104 -309.512716)
		(width 0.18288)
		(layer "In11.Cu")
		(net "M_D_CPU0_SA_DQS_DP<1>")
	)
	(segment
		(start 333.051912 -280.148538)
		(end 333.051912 -280.954226)
		(width 0.088646)
		(layer "In11.Cu")
		(net "M_D_CPU0_SA_DQS_DP<1>")
	)
	(segment
		(start 271.93621 -305.10353)
		(end 269.928594 -303.762156)
		(width 0.18288)
		(layer "In11.Cu")
		(net "M_D_CPU0_SA_DQS_DP<1>")
	)
	(segment
		(start 275.22551 -308.77383)
		(end 274.6756 -307.447442)
		(width 0.18288)
		(layer "In11.Cu")
		(net "M_D_CPU0_SA_DQS_DP<1>")
	)
	(segment
		(start 335.820512 -278.336502)
		(end 335.820512 -278.346408)
		(width 0.088646)
		(layer "In11.Cu")
		(net "M_D_CPU0_SA_DQS_DP<1>")
	)
	(segment
		(start 266.46251 -304.318416)
		(end 266.19073 -304.205386)
		(width 0.18288)
		(layer "In11.Cu")
		(net "M_D_CPU0_SA_DQS_DP<1>")
	)
	(segment
		(start 345.97086 -277.891494)
		(end 345.61526 -277.891494)
		(width 0.088646)
		(layer "In11.Cu")
		(net "M_D_CPU0_SA_DQS_DP<1>")
	)
	(segment
		(start 283.71673 -309.090822)
		(end 283.42844 -308.802532)
		(width 0.18288)
		(layer "In11.Cu")
		(net "M_D_CPU0_SA_DQS_DP<1>")
	)
	(segment
		(start 333.051912 -280.954226)
		(end 332.295246 -281.710892)
		(width 0.088646)
		(layer "In11.Cu")
		(net "M_D_CPU0_SA_DQS_DP<1>")
	)
	(segment
		(start 278.826214 -309.68061)
		(end 278.42972 -310.077104)
		(width 0.18288)
		(layer "In11.Cu")
		(net "M_D_CPU0_SA_DQS_DP<1>")
	)
	(segment
		(start 295.104566 -309.94096)
		(end 294.677846 -309.94096)
		(width 0.18288)
		(layer "In11.Cu")
		(net "M_D_CPU0_SA_DQS_DP<1>")
	)
	(segment
		(start 339.212174 -278.01824)
		(end 339.20176 -278.012144)
		(width 0.088646)
		(layer "In11.Cu")
		(net "M_D_CPU0_SA_DQS_DP<1>")
	)
	(segment
		(start 321.043808 -292.935914)
		(end 317.351664 -296.628058)
		(width 0.18288)
		(layer "In11.Cu")
		(net "M_D_CPU0_SA_DQS_DP<1>")
	)
	(segment
		(start 300.29912 -308.831488)
		(end 299.477684 -308.831488)
		(width 0.18288)
		(layer "In11.Cu")
		(net "M_D_CPU0_SA_DQS_DP<1>")
	)
	(segment
		(start 338.827364 -278.012144)
		(end 338.812632 -278.02078)
		(width 0.088646)
		(layer "In11.Cu")
		(net "M_D_CPU0_SA_DQS_DP<1>")
	)
	(segment
		(start 309.765446 -302.290734)
		(end 309.538116 -302.063404)
		(width 0.18288)
		(layer "In11.Cu")
		(net "M_D_CPU0_SA_DQS_DP<1>")
	)
	(segment
		(start 330.929996 -282.334462)
		(end 321.043808 -292.22065)
		(width 0.18288)
		(layer "In11.Cu")
		(net "M_D_CPU0_SA_DQS_DP<1>")
	)
	(segment
		(start 306.011834 -303.393856)
		(end 305.096418 -305.602386)
		(width 0.18288)
		(layer "In11.Cu")
		(net "M_D_CPU0_SA_DQS_DP<1>")
	)
	(segment
		(start 279.36444 -309.68061)
		(end 278.826214 -309.68061)
		(width 0.18288)
		(layer "In11.Cu")
		(net "M_D_CPU0_SA_DQS_DP<1>")
	)
	(segment
		(start 334.382872 -279.022302)
		(end 334.178148 -279.022302)
		(width 0.088646)
		(layer "In11.Cu")
		(net "M_D_CPU0_SA_DQS_DP<1>")
	)
	(segment
		(start 266.801092 -304.318416)
		(end 266.46251 -304.318416)
		(width 0.18288)
		(layer "In11.Cu")
		(net "M_D_CPU0_SA_DQS_DP<1>")
	)
	(segment
		(start 334.520286 -278.885142)
		(end 334.382872 -279.022302)
		(width 0.088646)
		(layer "In11.Cu")
		(net "M_D_CPU0_SA_DQS_DP<1>")
	)
	(segment
		(start 341.096346 -278.02078)
		(end 341.081614 -278.012144)
		(width 0.088646)
		(layer "In11.Cu")
		(net "M_D_CPU0_SA_DQS_DP<1>")
	)
	(segment
		(start 274.6756 -306.915566)
		(end 274.55749 -306.630832)
		(width 0.18288)
		(layer "In11.Cu")
		(net "M_D_CPU0_SA_DQS_DP<1>")
	)
	(segment
		(start 269.92834 -303.761902)
		(end 269.75816 -303.71034)
		(width 0.18288)
		(layer "In11.Cu")
		(net "M_D_CPU0_SA_DQS_DP<1>")
	)
	(segment
		(start 308.794912 -302.063404)
		(end 308.246018 -302.612552)
		(width 0.18288)
		(layer "In11.Cu")
		(net "M_D_CPU0_SA_DQS_DP<1>")
	)
	(segment
		(start 317.351664 -298.884086)
		(end 315.093858 -301.141892)
		(width 0.18288)
		(layer "In11.Cu")
		(net "M_D_CPU0_SA_DQS_DP<1>")
	)
	(segment
		(start 305.096418 -305.602386)
		(end 304.234342 -306.464462)
		(width 0.18288)
		(layer "In11.Cu")
		(net "M_D_CPU0_SA_DQS_DP<1>")
	)
	(segment
		(start 293.613332 -309.364634)
		(end 292.932358 -309.082694)
		(width 0.18288)
		(layer "In11.Cu")
		(net "M_D_CPU0_SA_DQS_DP<1>")
	)
	(segment
		(start 269.014448 -303.992788)
		(end 268.648942 -303.992788)
		(width 0.18288)
		(layer "In11.Cu")
		(net "M_D_CPU0_SA_DQS_DP<1>")
	)
	(segment
		(start 292.128194 -309.230014)
		(end 291.845492 -309.512716)
		(width 0.18288)
		(layer "In11.Cu")
		(net "M_D_CPU0_SA_DQS_DP<1>")
	)
	(segment
		(start 280.264616 -309.677562)
		(end 280.001218 -309.94096)
		(width 0.18288)
		(layer "In11.Cu")
		(net "M_D_CPU0_SA_DQS_DP<1>")
	)
	(segment
		(start 294.435276 -309.69839)
		(end 293.947342 -309.69839)
		(width 0.18288)
		(layer "In11.Cu")
		(net "M_D_CPU0_SA_DQS_DP<1>")
	)
	(segment
		(start 268.340586 -303.684432)
		(end 267.940282 -303.684432)
		(width 0.18288)
		(layer "In11.Cu")
		(net "M_D_CPU0_SA_DQS_DP<1>")
	)
	(segment
		(start 292.932358 -309.082694)
		(end 292.483794 -309.082694)
		(width 0.18288)
		(layer "In11.Cu")
		(net "M_D_CPU0_SA_DQS_DP<1>")
	)
	(segment
		(start 321.043808 -292.22065)
		(end 321.043808 -292.935914)
		(width 0.18288)
		(layer "In11.Cu")
		(net "M_D_CPU0_SA_DQS_DP<1>")
	)
	(segment
		(start 312.892186 -301.495968)
		(end 311.591452 -302.034702)
		(width 0.18288)
		(layer "In11.Cu")
		(net "M_D_CPU0_SA_DQS_DP<1>")
	)
	(segment
		(start 310.510174 -302.034702)
		(end 310.254142 -302.290734)
		(width 0.18288)
		(layer "In11.Cu")
		(net "M_D_CPU0_SA_DQS_DP<1>")
	)
	(segment
		(start 269.75816 -303.71034)
		(end 269.296896 -303.71034)
		(width 0.18288)
		(layer "In11.Cu")
		(net "M_D_CPU0_SA_DQS_DP<1>")
	)
	(segment
		(start 267.663676 -303.961038)
		(end 266.801092 -304.318416)
		(width 0.18288)
		(layer "In11.Cu")
		(net "M_D_CPU0_SA_DQS_DP<1>")
	)
	(segment
		(start 332.295246 -281.795728)
		(end 331.756512 -282.334462)
		(width 0.18288)
		(layer "In11.Cu")
		(net "M_D_CPU0_SA_DQS_DP<1>")
	)
	(segment
		(start 272.293334 -305.4604)
		(end 272.293334 -305.460654)
		(width 0.18288)
		(layer "In11.Cu")
		(net "M_D_CPU0_SA_DQS_DP<1>")
	)
	(segment
		(start 277.98649 -310.260746)
		(end 277.417022 -310.260746)
		(width 0.18288)
		(layer "In11.Cu")
		(net "M_D_CPU0_SA_DQS_DP<1>")
	)
	(segment
		(start 283.42844 -308.802532)
		(end 283.327602 -308.802532)
		(width 0.18288)
		(layer "In11.Cu")
		(net "M_D_CPU0_SA_DQS_DP<1>")
	)
	(segment
		(start 287.594802 -308.827424)
		(end 284.373828 -308.827424)
		(width 0.18288)
		(layer "In11.Cu")
		(net "M_D_CPU0_SA_DQS_DP<1>")
	)
	(segment
		(start 344.84056 -278.01189)
		(end 344.840814 -278.012144)
		(width 0.088646)
		(layer "In11.Cu")
		(net "M_D_CPU0_SA_DQS_DP<1>")
	)
	(segment
		(start 284.11043 -309.090822)
		(end 283.71673 -309.090822)
		(width 0.18288)
		(layer "In11.Cu")
		(net "M_D_CPU0_SA_DQS_DP<1>")
	)
	(segment
		(start 334.598264 -278.82596)
		(end 334.597756 -278.826214)
		(width 0.088646)
		(layer "In11.Cu")
		(net "M_D_CPU0_SA_DQS_DP<1>")
	)
	(segment
		(start 289.249104 -309.512716)
		(end 287.594802 -308.827424)
		(width 0.18288)
		(layer "In11.Cu")
		(net "M_D_CPU0_SA_DQS_DP<1>")
	)
	(segment
		(start 307.220874 -303.03724)
		(end 306.36845 -303.03724)
		(width 0.18288)
		(layer "In11.Cu")
		(net "M_D_CPU0_SA_DQS_DP<1>")
	)
	(segment
		(start 293.947342 -309.69839)
		(end 293.613332 -309.364634)
		(width 0.18288)
		(layer "In11.Cu")
		(net "M_D_CPU0_SA_DQS_DP<1>")
	)
	(segment
		(start 313.594242 -301.159672)
		(end 313.228482 -301.159672)
		(width 0.18288)
		(layer "In11.Cu")
		(net "M_D_CPU0_SA_DQS_DP<1>")
	)
	(segment
		(start 268.648942 -303.992788)
		(end 268.340586 -303.684432)
		(width 0.18288)
		(layer "In11.Cu")
		(net "M_D_CPU0_SA_DQS_DP<1>")
	)
	(segment
		(start 336.397092 -278.02078)
		(end 336.38236 -278.012144)
		(width 0.088646)
		(layer "In11.Cu")
		(net "M_D_CPU0_SA_DQS_DP<1>")
	)
	(segment
		(start 342.975946 -278.02078)
		(end 342.961214 -278.012144)
		(width 0.088646)
		(layer "In11.Cu")
		(net "M_D_CPU0_SA_DQS_DP<1>")
	)
	(segment
		(start 340.156546 -278.02078)
		(end 340.141814 -278.012144)
		(width 0.088646)
		(layer "In11.Cu")
		(net "M_D_CPU0_SA_DQS_DP<1>")
	)
	(segment
		(start 334.178148 -279.022302)
		(end 333.051912 -280.148538)
		(width 0.088646)
		(layer "In11.Cu")
		(net "M_D_CPU0_SA_DQS_DP<1>")
	)
	(segment
		(start 314.298838 -301.440088)
		(end 313.874658 -301.440088)
		(width 0.18288)
		(layer "In11.Cu")
		(net "M_D_CPU0_SA_DQS_DP<1>")
	)
	(segment
		(start 301.557182 -307.573426)
		(end 300.29912 -308.831488)
		(width 0.18288)
		(layer "In11.Cu")
		(net "M_D_CPU0_SA_DQS_DP<1>")
	)
	(segment
		(start 274.55749 -306.630832)
		(end 274.160996 -306.234084)
		(width 0.18288)
		(layer "In11.Cu")
		(net "M_D_CPU0_SA_DQS_DP<1>")
	)
	(segment
		(start 296.430192 -309.673498)
		(end 295.372028 -309.673498)
		(width 0.18288)
		(layer "In11.Cu")
		(net "M_D_CPU0_SA_DQS_DP<1>")
	)
	(segment
		(start 345.975686 -277.888954)
		(end 345.97086 -277.891494)
		(width 0.088646)
		(layer "In11.Cu")
		(net "M_D_CPU0_SA_DQS_DP<1>")
	)
	(segment
		(start 313.228482 -301.159672)
		(end 312.892186 -301.495968)
		(width 0.18288)
		(layer "In11.Cu")
		(net "M_D_CPU0_SA_DQS_DP<1>")
	)
	(segment
		(start 277.417022 -310.260746)
		(end 276.21357 -309.762398)
		(width 0.18288)
		(layer "In11.Cu")
		(net "M_D_CPU0_SA_DQS_DP<1>")
	)
	(segment
		(start 265.00963 -303.28616)
		(end 264.729214 -303.566576)
		(width 0.18288)
		(layer "In11.Cu")
		(net "M_D_CPU0_SA_DQS_DP<1>")
	)
	(arc
		(start 347.002862 -277.522432)
		(mid 346.826841 -277.545269)
		(end 346.662502 -277.612348)
		(width 0.088646)
		(layer "In11.Cu")
		(net "M_D_CPU0_SA_DQS_DP<1>")
	)
	(arc
		(start 343.526618 -278.012144)
		(mid 343.252389 -278.088069)
		(end 342.975946 -278.02078)
		(width 0.088646)
		(layer "In11.Cu")
		(net "M_D_CPU0_SA_DQS_DP<1>")
	)
	(arc
		(start 335.999074 -278.017224)
		(mid 335.86816 -278.153584)
		(end 335.820512 -278.336502)
		(width 0.088646)
		(layer "In11.Cu")
		(net "M_D_CPU0_SA_DQS_DP<1>")
	)
	(arc
		(start 340.141814 -278.012144)
		(mid 339.954616 -277.962001)
		(end 339.767418 -278.012144)
		(width 0.088646)
		(layer "In11.Cu")
		(net "M_D_CPU0_SA_DQS_DP<1>")
	)
	(arc
		(start 346.237306 -277.854156)
		(mid 346.138464 -277.891666)
		(end 346.032836 -277.895812)
		(width 0.088646)
		(layer "In11.Cu")
		(net "M_D_CPU0_SA_DQS_DP<1>")
	)
	(arc
		(start 338.26196 -278.012144)
		(mid 338.074762 -277.962001)
		(end 337.887564 -278.012144)
		(width 0.088646)
		(layer "In11.Cu")
		(net "M_D_CPU0_SA_DQS_DP<1>")
	)
	(arc
		(start 335.538064 -278.82596)
		(mid 335.255362 -278.901736)
		(end 334.97266 -278.82596)
		(width 0.088646)
		(layer "In11.Cu")
		(net "M_D_CPU0_SA_DQS_DP<1>")
	)
	(arc
		(start 342.021414 -278.012144)
		(mid 341.834216 -277.962001)
		(end 341.647018 -278.012144)
		(width 0.088646)
		(layer "In11.Cu")
		(net "M_D_CPU0_SA_DQS_DP<1>")
	)
	(arc
		(start 342.961214 -278.012144)
		(mid 342.774016 -277.962001)
		(end 342.586818 -278.012144)
		(width 0.088646)
		(layer "In11.Cu")
		(net "M_D_CPU0_SA_DQS_DP<1>")
	)
	(arc
		(start 337.887564 -278.012144)
		(mid 337.604862 -278.087886)
		(end 337.32216 -278.012144)
		(width 0.088646)
		(layer "In11.Cu")
		(net "M_D_CPU0_SA_DQS_DP<1>")
	)
	(arc
		(start 339.767418 -278.012144)
		(mid 339.490605 -278.08798)
		(end 339.212174 -278.01824)
		(width 0.088646)
		(layer "In11.Cu")
		(net "M_D_CPU0_SA_DQS_DP<1>")
	)
	(arc
		(start 341.081614 -278.012144)
		(mid 340.894416 -277.962001)
		(end 340.707218 -278.012144)
		(width 0.088646)
		(layer "In11.Cu")
		(net "M_D_CPU0_SA_DQS_DP<1>")
	)
	(arc
		(start 342.586818 -278.012144)
		(mid 342.312589 -278.088069)
		(end 342.036146 -278.02078)
		(width 0.088646)
		(layer "In11.Cu")
		(net "M_D_CPU0_SA_DQS_DP<1>")
	)
	(arc
		(start 334.597756 -278.826214)
		(mid 334.557101 -278.853153)
		(end 334.520286 -278.885142)
		(width 0.088646)
		(layer "In11.Cu")
		(net "M_D_CPU0_SA_DQS_DP<1>")
	)
	(arc
		(start 345.39174 -278.020272)
		(mid 345.115075 -278.087743)
		(end 344.84056 -278.01189)
		(width 0.088646)
		(layer "In11.Cu")
		(net "M_D_CPU0_SA_DQS_DP<1>")
	)
	(arc
		(start 341.647018 -278.012144)
		(mid 341.372789 -278.088069)
		(end 341.096346 -278.02078)
		(width 0.088646)
		(layer "In11.Cu")
		(net "M_D_CPU0_SA_DQS_DP<1>")
	)
	(arc
		(start 336.947764 -278.012144)
		(mid 336.673565 -278.087979)
		(end 336.397092 -278.02078)
		(width 0.088646)
		(layer "In11.Cu")
		(net "M_D_CPU0_SA_DQS_DP<1>")
	)
	(arc
		(start 339.20176 -278.012144)
		(mid 339.014735 -277.962001)
		(end 338.827618 -278.01189)
		(width 0.088646)
		(layer "In11.Cu")
		(net "M_D_CPU0_SA_DQS_DP<1>")
	)
	(arc
		(start 335.820512 -278.346408)
		(mid 335.742401 -278.623357)
		(end 335.538064 -278.82596)
		(width 0.088646)
		(layer "In11.Cu")
		(net "M_D_CPU0_SA_DQS_DP<1>")
	)
	(arc
		(start 336.38236 -278.012144)
		(mid 336.195162 -277.962001)
		(end 336.007964 -278.012144)
		(width 0.088646)
		(layer "In11.Cu")
		(net "M_D_CPU0_SA_DQS_DP<1>")
	)
	(arc
		(start 344.840814 -278.012144)
		(mid 344.653616 -277.962001)
		(end 344.466418 -278.012144)
		(width 0.088646)
		(layer "In11.Cu")
		(net "M_D_CPU0_SA_DQS_DP<1>")
	)
	(arc
		(start 344.466418 -278.012144)
		(mid 344.192189 -278.088069)
		(end 343.915746 -278.02078)
		(width 0.088646)
		(layer "In11.Cu")
		(net "M_D_CPU0_SA_DQS_DP<1>")
	)
	(arc
		(start 334.97266 -278.82596)
		(mid 334.785462 -278.775817)
		(end 334.598264 -278.82596)
		(width 0.088646)
		(layer "In11.Cu")
		(net "M_D_CPU0_SA_DQS_DP<1>")
	)
	(arc
		(start 337.32216 -278.012144)
		(mid 337.134962 -277.962001)
		(end 336.947764 -278.012144)
		(width 0.088646)
		(layer "In11.Cu")
		(net "M_D_CPU0_SA_DQS_DP<1>")
	)
	(arc
		(start 340.707218 -278.012144)
		(mid 340.432989 -278.088069)
		(end 340.156546 -278.02078)
		(width 0.088646)
		(layer "In11.Cu")
		(net "M_D_CPU0_SA_DQS_DP<1>")
	)
	(arc
		(start 343.901014 -278.012144)
		(mid 343.713816 -277.962001)
		(end 343.526618 -278.012144)
		(width 0.088646)
		(layer "In11.Cu")
		(net "M_D_CPU0_SA_DQS_DP<1>")
	)
	(arc
		(start 338.812632 -278.02078)
		(mid 338.536191 -278.087946)
		(end 338.26196 -278.012144)
		(width 0.088646)
		(layer "In11.Cu")
		(net "M_D_CPU0_SA_DQS_DP<1>")
	)
	(segment
		(start 259.302758 -313.341766)
		(end 259.065776 -313.341766)
		(width 0.101854)
		(layer "F.Cu")
		(net "M_D_CPU0_SA_DQS_DP<0>")
	)
	(segment
		(start 256.879598 -312.655458)
		(end 256.618486 -312.91657)
		(width 0.20066)
		(layer "F.Cu")
		(net "M_D_CPU0_SA_DQS_DP<0>")
	)
	(segment
		(start 261.381494 -313.341766)
		(end 261.058152 -313.341766)
		(width 0.101854)
		(layer "F.Cu")
		(net "M_D_CPU0_SA_DQS_DP<0>")
	)
	(segment
		(start 262.120634 -313.080654)
		(end 261.794752 -313.080654)
		(width 0.20066)
		(layer "F.Cu")
		(net "M_D_CPU0_SA_DQS_DP<0>")
	)
	(segment
		(start 257.940556 -313.080654)
		(end 257.30454 -312.655458)
		(width 0.20066)
		(layer "F.Cu")
		(net "M_D_CPU0_SA_DQS_DP<0>")
	)
	(segment
		(start 263.624314 -312.91657)
		(end 263.075674 -312.91657)
		(width 0.20066)
		(layer "F.Cu")
		(net "M_D_CPU0_SA_DQS_DP<0>")
	)
	(segment
		(start 262.54583 -312.655458)
		(end 262.120634 -313.080654)
		(width 0.20066)
		(layer "F.Cu")
		(net "M_D_CPU0_SA_DQS_DP<0>")
	)
	(segment
		(start 259.065776 -313.341766)
		(end 259.056378 -313.351164)
		(width 0.101854)
		(layer "F.Cu")
		(net "M_D_CPU0_SA_DQS_DP<0>")
	)
	(segment
		(start 258.838192 -313.351164)
		(end 258.567682 -313.080654)
		(width 0.20066)
		(layer "F.Cu")
		(net "M_D_CPU0_SA_DQS_DP<0>")
	)
	(segment
		(start 264.729214 -312.91657)
		(end 263.624314 -312.91657)
		(width 0.20066)
		(layer "F.Cu")
		(net "M_D_CPU0_SA_DQS_DP<0>")
	)
	(segment
		(start 259.056378 -313.351164)
		(end 258.838192 -313.351164)
		(width 0.20066)
		(layer "F.Cu")
		(net "M_D_CPU0_SA_DQS_DP<0>")
	)
	(segment
		(start 261.058152 -313.341766)
		(end 259.302758 -313.341766)
		(width 0.1016)
		(layer "F.Cu")
		(net "M_D_CPU0_SA_DQS_DP<0>")
	)
	(segment
		(start 261.53364 -313.341766)
		(end 261.381494 -313.341766)
		(width 0.20066)
		(layer "F.Cu")
		(net "M_D_CPU0_SA_DQS_DP<0>")
	)
	(segment
		(start 263.075674 -312.91657)
		(end 262.814562 -312.655458)
		(width 0.20066)
		(layer "F.Cu")
		(net "M_D_CPU0_SA_DQS_DP<0>")
	)
	(segment
		(start 258.567682 -313.080654)
		(end 257.940556 -313.080654)
		(width 0.20066)
		(layer "F.Cu")
		(net "M_D_CPU0_SA_DQS_DP<0>")
	)
	(segment
		(start 256.618486 -312.91657)
		(end 256.080514 -312.91657)
		(width 0.20066)
		(layer "F.Cu")
		(net "M_D_CPU0_SA_DQS_DP<0>")
	)
	(segment
		(start 262.814562 -312.655458)
		(end 262.54583 -312.655458)
		(width 0.20066)
		(layer "F.Cu")
		(net "M_D_CPU0_SA_DQS_DP<0>")
	)
	(segment
		(start 257.30454 -312.655458)
		(end 256.879598 -312.655458)
		(width 0.20066)
		(layer "F.Cu")
		(net "M_D_CPU0_SA_DQS_DP<0>")
	)
	(segment
		(start 261.794752 -313.080654)
		(end 261.53364 -313.341766)
		(width 0.20066)
		(layer "F.Cu")
		(net "M_D_CPU0_SA_DQS_DP<0>")
	)
	(arc
		(start 343.713562 -274.54479)
		(mid 343.713625 -274.81276)
		(end 343.713816 -275.08073)
		(width 0.20066)
		(layer "F.Cu")
		(net "M_D_CPU0_SA_DQS_DP<0>")
	)
	(segment
		(start 285.88716 -314.392818)
		(end 284.995112 -314.762134)
		(width 0.18288)
		(layer "In6.Cu")
		(net "M_D_CPU0_SA_DQS_DP<0>")
	)
	(segment
		(start 276.647656 -312.399172)
		(end 274.128484 -312.399172)
		(width 0.18288)
		(layer "In6.Cu")
		(net "M_D_CPU0_SA_DQS_DP<0>")
	)
	(segment
		(start 338.357464 -275.570188)
		(end 338.357464 -275.570442)
		(width 0.088646)
		(layer "In6.Cu")
		(net "M_D_CPU0_SA_DQS_DP<0>")
	)
	(segment
		(start 332.017878 -280.960576)
		(end 331.99451 -280.960576)
		(width 0.088646)
		(layer "In6.Cu")
		(net "M_D_CPU0_SA_DQS_DP<0>")
	)
	(segment
		(start 272.492724 -313.07659)
		(end 269.306802 -313.07659)
		(width 0.18288)
		(layer "In6.Cu")
		(net "M_D_CPU0_SA_DQS_DP<0>")
	)
	(segment
		(start 298.806362 -307.391562)
		(end 298.503594 -307.088794)
		(width 0.18288)
		(layer "In6.Cu")
		(net "M_D_CPU0_SA_DQS_DP<0>")
	)
	(segment
		(start 299.284898 -307.391562)
		(end 298.806362 -307.391562)
		(width 0.18288)
		(layer "In6.Cu")
		(net "M_D_CPU0_SA_DQS_DP<0>")
	)
	(segment
		(start 340.61146 -275.570442)
		(end 340.61146 -275.570188)
		(width 0.088646)
		(layer "In6.Cu")
		(net "M_D_CPU0_SA_DQS_DP<0>")
	)
	(segment
		(start 310.24703 -300.591728)
		(end 309.768494 -300.591728)
		(width 0.18288)
		(layer "In6.Cu")
		(net "M_D_CPU0_SA_DQS_DP<0>")
	)
	(segment
		(start 332.077822 -280.900632)
		(end 332.017878 -280.960576)
		(width 0.088646)
		(layer "In6.Cu")
		(net "M_D_CPU0_SA_DQS_DP<0>")
	)
	(segment
		(start 314.997592 -299.449236)
		(end 314.571634 -299.449236)
		(width 0.18288)
		(layer "In6.Cu")
		(net "M_D_CPU0_SA_DQS_DP<0>")
	)
	(segment
		(start 296.883836 -307.96103)
		(end 296.278808 -308.566058)
		(width 0.18288)
		(layer "In6.Cu")
		(net "M_D_CPU0_SA_DQS_DP<0>")
	)
	(segment
		(start 338.357464 -275.570442)
		(end 338.348574 -275.575522)
		(width 0.088646)
		(layer "In6.Cu")
		(net "M_D_CPU0_SA_DQS_DP<0>")
	)
	(segment
		(start 267.629132 -313.063636)
		(end 267.092176 -312.52668)
		(width 0.18288)
		(layer "In6.Cu")
		(net "M_D_CPU0_SA_DQS_DP<0>")
	)
	(segment
		(start 284.395672 -314.762134)
		(end 284.116018 -315.041788)
		(width 0.18288)
		(layer "In6.Cu")
		(net "M_D_CPU0_SA_DQS_DP<0>")
	)
	(segment
		(start 297.511724 -307.700934)
		(end 296.883836 -307.96103)
		(width 0.18288)
		(layer "In6.Cu")
		(net "M_D_CPU0_SA_DQS_DP<0>")
	)
	(segment
		(start 336.95386 -278.008588)
		(end 336.947764 -278.012144)
		(width 0.088646)
		(layer "In6.Cu")
		(net "M_D_CPU0_SA_DQS_DP<0>")
	)
	(segment
		(start 334.517492 -278.02078)
		(end 334.50276 -278.012144)
		(width 0.088646)
		(layer "In6.Cu")
		(net "M_D_CPU0_SA_DQS_DP<0>")
	)
	(segment
		(start 343.149936 -275.297646)
		(end 342.94826 -275.412454)
		(width 0.088646)
		(layer "In6.Cu")
		(net "M_D_CPU0_SA_DQS_DP<0>")
	)
	(segment
		(start 331.99451 -280.960576)
		(end 331.452728 -280.960576)
		(width 0.18288)
		(layer "In6.Cu")
		(net "M_D_CPU0_SA_DQS_DP<0>")
	)
	(segment
		(start 337.700112 -276.708616)
		(end 337.700112 -276.718522)
		(width 0.088646)
		(layer "In6.Cu")
		(net "M_D_CPU0_SA_DQS_DP<0>")
	)
	(segment
		(start 335.457292 -278.02078)
		(end 335.44256 -278.012144)
		(width 0.088646)
		(layer "In6.Cu")
		(net "M_D_CPU0_SA_DQS_DP<0>")
	)
	(segment
		(start 298.123864 -307.088794)
		(end 297.511724 -307.700934)
		(width 0.18288)
		(layer "In6.Cu")
		(net "M_D_CPU0_SA_DQS_DP<0>")
	)
	(segment
		(start 280.05151 -314.191396)
		(end 279.618694 -314.191396)
		(width 0.18288)
		(layer "In6.Cu")
		(net "M_D_CPU0_SA_DQS_DP<0>")
	)
	(segment
		(start 342.326214 -275.449792)
		(end 342.102694 -275.57857)
		(width 0.088646)
		(layer "In6.Cu")
		(net "M_D_CPU0_SA_DQS_DP<0>")
	)
	(segment
		(start 333.848202 -278.27351)
		(end 333.848202 -278.88565)
		(width 0.088646)
		(layer "In6.Cu")
		(net "M_D_CPU0_SA_DQS_DP<0>")
	)
	(segment
		(start 314.571634 -299.449236)
		(end 314.277248 -299.743622)
		(width 0.18288)
		(layer "In6.Cu")
		(net "M_D_CPU0_SA_DQS_DP<0>")
	)
	(segment
		(start 304.709068 -304.541936)
		(end 302.113442 -305.618134)
		(width 0.18288)
		(layer "In6.Cu")
		(net "M_D_CPU0_SA_DQS_DP<0>")
	)
	(segment
		(start 300.18101 -307.111908)
		(end 299.564552 -307.111908)
		(width 0.18288)
		(layer "In6.Cu")
		(net "M_D_CPU0_SA_DQS_DP<0>")
	)
	(segment
		(start 298.503594 -307.088794)
		(end 298.123864 -307.088794)
		(width 0.18288)
		(layer "In6.Cu")
		(net "M_D_CPU0_SA_DQS_DP<0>")
	)
	(segment
		(start 342.74379 -275.45411)
		(end 342.68664 -275.447252)
		(width 0.088646)
		(layer "In6.Cu")
		(net "M_D_CPU0_SA_DQS_DP<0>")
	)
	(segment
		(start 264.998962 -312.646822)
		(end 264.729214 -312.91657)
		(width 0.18288)
		(layer "In6.Cu")
		(net "M_D_CPU0_SA_DQS_DP<0>")
	)
	(segment
		(start 292.112446 -311.165494)
		(end 286.994346 -313.285632)
		(width 0.18288)
		(layer "In6.Cu")
		(net "M_D_CPU0_SA_DQS_DP<0>")
	)
	(segment
		(start 286.994346 -313.285632)
		(end 285.88716 -314.392818)
		(width 0.18288)
		(layer "In6.Cu")
		(net "M_D_CPU0_SA_DQS_DP<0>")
	)
	(segment
		(start 342.68664 -275.447252)
		(end 342.681814 -275.449792)
		(width 0.088646)
		(layer "In6.Cu")
		(net "M_D_CPU0_SA_DQS_DP<0>")
	)
	(segment
		(start 284.995112 -314.762134)
		(end 284.395672 -314.762134)
		(width 0.18288)
		(layer "In6.Cu")
		(net "M_D_CPU0_SA_DQS_DP<0>")
	)
	(segment
		(start 310.515508 -300.32325)
		(end 310.24703 -300.591728)
		(width 0.18288)
		(layer "In6.Cu")
		(net "M_D_CPU0_SA_DQS_DP<0>")
	)
	(segment
		(start 280.29789 -313.945016)
		(end 280.05151 -314.191396)
		(width 0.18288)
		(layer "In6.Cu")
		(net "M_D_CPU0_SA_DQS_DP<0>")
	)
	(segment
		(start 311.112154 -300.32325)
		(end 310.515508 -300.32325)
		(width 0.18288)
		(layer "In6.Cu")
		(net "M_D_CPU0_SA_DQS_DP<0>")
	)
	(segment
		(start 309.084726 -300.300898)
		(end 308.48554 -300.900084)
		(width 0.18288)
		(layer "In6.Cu")
		(net "M_D_CPU0_SA_DQS_DP<0>")
	)
	(segment
		(start 269.306802 -313.07659)
		(end 269.041626 -313.341766)
		(width 0.18288)
		(layer "In6.Cu")
		(net "M_D_CPU0_SA_DQS_DP<0>")
	)
	(segment
		(start 299.564552 -307.111908)
		(end 299.284898 -307.391562)
		(width 0.18288)
		(layer "In6.Cu")
		(net "M_D_CPU0_SA_DQS_DP<0>")
	)
	(segment
		(start 283.718762 -315.041788)
		(end 283.421582 -314.744608)
		(width 0.18288)
		(layer "In6.Cu")
		(net "M_D_CPU0_SA_DQS_DP<0>")
	)
	(segment
		(start 265.781028 -312.646822)
		(end 264.998962 -312.646822)
		(width 0.18288)
		(layer "In6.Cu")
		(net "M_D_CPU0_SA_DQS_DP<0>")
	)
	(segment
		(start 334.050386 -278.071326)
		(end 333.848202 -278.27351)
		(width 0.088646)
		(layer "In6.Cu")
		(net "M_D_CPU0_SA_DQS_DP<0>")
	)
	(segment
		(start 343.52992 -275.134578)
		(end 343.229438 -275.258784)
		(width 0.088646)
		(layer "In6.Cu")
		(net "M_D_CPU0_SA_DQS_DP<0>")
	)
	(segment
		(start 283.421582 -314.744608)
		(end 282.992068 -314.744608)
		(width 0.18288)
		(layer "In6.Cu")
		(net "M_D_CPU0_SA_DQS_DP<0>")
	)
	(segment
		(start 312.22061 -300.064424)
		(end 311.37098 -300.064424)
		(width 0.18288)
		(layer "In6.Cu")
		(net "M_D_CPU0_SA_DQS_DP<0>")
	)
	(segment
		(start 279.324308 -313.89701)
		(end 278.844248 -313.89701)
		(width 0.18288)
		(layer "In6.Cu")
		(net "M_D_CPU0_SA_DQS_DP<0>")
	)
	(segment
		(start 337.416902 -277.198582)
		(end 337.415124 -277.199598)
		(width 0.088646)
		(layer "In6.Cu")
		(net "M_D_CPU0_SA_DQS_DP<0>")
	)
	(segment
		(start 274.128484 -312.399172)
		(end 272.492724 -313.07659)
		(width 0.18288)
		(layer "In6.Cu")
		(net "M_D_CPU0_SA_DQS_DP<0>")
	)
	(segment
		(start 266.317222 -312.424826)
		(end 265.781028 -312.646822)
		(width 0.18288)
		(layer "In6.Cu")
		(net "M_D_CPU0_SA_DQS_DP<0>")
	)
	(segment
		(start 292.769544 -310.508904)
		(end 292.112446 -311.165494)
		(width 0.18288)
		(layer "In6.Cu")
		(net "M_D_CPU0_SA_DQS_DP<0>")
	)
	(segment
		(start 332.658212 -280.63317)
		(end 332.39075 -280.900632)
		(width 0.088646)
		(layer "In6.Cu")
		(net "M_D_CPU0_SA_DQS_DP<0>")
	)
	(segment
		(start 307.759608 -301.20082)
		(end 306.608226 -302.352202)
		(width 0.18288)
		(layer "In6.Cu")
		(net "M_D_CPU0_SA_DQS_DP<0>")
	)
	(segment
		(start 294.706548 -309.941976)
		(end 294.415464 -309.650892)
		(width 0.18288)
		(layer "In6.Cu")
		(net "M_D_CPU0_SA_DQS_DP<0>")
	)
	(segment
		(start 341.551514 -275.570188)
		(end 341.55126 -275.570442)
		(width 0.088646)
		(layer "In6.Cu")
		(net "M_D_CPU0_SA_DQS_DP<0>")
	)
	(segment
		(start 296.278808 -309.209694)
		(end 295.826434 -309.662068)
		(width 0.18288)
		(layer "In6.Cu")
		(net "M_D_CPU0_SA_DQS_DP<0>")
	)
	(segment
		(start 306.608226 -302.352202)
		(end 306.402486 -302.848518)
		(width 0.18288)
		(layer "In6.Cu")
		(net "M_D_CPU0_SA_DQS_DP<0>")
	)
	(segment
		(start 268.37132 -313.063636)
		(end 267.629132 -313.063636)
		(width 0.18288)
		(layer "In6.Cu")
		(net "M_D_CPU0_SA_DQS_DP<0>")
	)
	(segment
		(start 339.297264 -275.570188)
		(end 339.282532 -275.578824)
		(width 0.088646)
		(layer "In6.Cu")
		(net "M_D_CPU0_SA_DQS_DP<0>")
	)
	(segment
		(start 331.452728 -280.960576)
		(end 315.818012 -296.595292)
		(width 0.18288)
		(layer "In6.Cu")
		(net "M_D_CPU0_SA_DQS_DP<0>")
	)
	(segment
		(start 311.37098 -300.064424)
		(end 311.112154 -300.32325)
		(width 0.18288)
		(layer "In6.Cu")
		(net "M_D_CPU0_SA_DQS_DP<0>")
	)
	(segment
		(start 295.184576 -309.941976)
		(end 294.706548 -309.941976)
		(width 0.18288)
		(layer "In6.Cu")
		(net "M_D_CPU0_SA_DQS_DP<0>")
	)
	(segment
		(start 315.818012 -296.595292)
		(end 315.818012 -298.628816)
		(width 0.18288)
		(layer "In6.Cu")
		(net "M_D_CPU0_SA_DQS_DP<0>")
	)
	(segment
		(start 309.768494 -300.591728)
		(end 309.477664 -300.300898)
		(width 0.18288)
		(layer "In6.Cu")
		(net "M_D_CPU0_SA_DQS_DP<0>")
	)
	(segment
		(start 333.848202 -278.88565)
		(end 332.658212 -280.07564)
		(width 0.088646)
		(layer "In6.Cu")
		(net "M_D_CPU0_SA_DQS_DP<0>")
	)
	(segment
		(start 312.785506 -299.499528)
		(end 312.22061 -300.064424)
		(width 0.18288)
		(layer "In6.Cu")
		(net "M_D_CPU0_SA_DQS_DP<0>")
	)
	(segment
		(start 266.846304 -312.424826)
		(end 266.317222 -312.424826)
		(width 0.18288)
		(layer "In6.Cu")
		(net "M_D_CPU0_SA_DQS_DP<0>")
	)
	(segment
		(start 296.278808 -308.566058)
		(end 296.278808 -309.209694)
		(width 0.18288)
		(layer "In6.Cu")
		(net "M_D_CPU0_SA_DQS_DP<0>")
	)
	(segment
		(start 337.414362 -277.200106)
		(end 337.409536 -277.202646)
		(width 0.088646)
		(layer "In6.Cu")
		(net "M_D_CPU0_SA_DQS_DP<0>")
	)
	(segment
		(start 282.293314 -314.045854)
		(end 282.050236 -313.945016)
		(width 0.18288)
		(layer "In6.Cu")
		(net "M_D_CPU0_SA_DQS_DP<0>")
	)
	(segment
		(start 277.84044 -312.893202)
		(end 276.647656 -312.399172)
		(width 0.18288)
		(layer "In6.Cu")
		(net "M_D_CPU0_SA_DQS_DP<0>")
	)
	(segment
		(start 282.050236 -313.945016)
		(end 280.29789 -313.945016)
		(width 0.18288)
		(layer "In6.Cu")
		(net "M_D_CPU0_SA_DQS_DP<0>")
	)
	(segment
		(start 337.417664 -277.198074)
		(end 337.416902 -277.198582)
		(width 0.088646)
		(layer "In6.Cu")
		(net "M_D_CPU0_SA_DQS_DP<0>")
	)
	(segment
		(start 314.277248 -299.743622)
		(end 313.901836 -299.743622)
		(width 0.18288)
		(layer "In6.Cu")
		(net "M_D_CPU0_SA_DQS_DP<0>")
	)
	(segment
		(start 295.464484 -309.662068)
		(end 295.184576 -309.941976)
		(width 0.18288)
		(layer "In6.Cu")
		(net "M_D_CPU0_SA_DQS_DP<0>")
	)
	(segment
		(start 293.715948 -310.116982)
		(end 292.769544 -310.508904)
		(width 0.18288)
		(layer "In6.Cu")
		(net "M_D_CPU0_SA_DQS_DP<0>")
	)
	(segment
		(start 337.415124 -277.199598)
		(end 337.414362 -277.200106)
		(width 0.088646)
		(layer "In6.Cu")
		(net "M_D_CPU0_SA_DQS_DP<0>")
	)
	(segment
		(start 313.901836 -299.743622)
		(end 313.657742 -299.499528)
		(width 0.18288)
		(layer "In6.Cu")
		(net "M_D_CPU0_SA_DQS_DP<0>")
	)
	(segment
		(start 309.477664 -300.300898)
		(end 309.084726 -300.300898)
		(width 0.18288)
		(layer "In6.Cu")
		(net "M_D_CPU0_SA_DQS_DP<0>")
	)
	(segment
		(start 341.176864 -275.570442)
		(end 341.162132 -275.579078)
		(width 0.088646)
		(layer "In6.Cu")
		(net "M_D_CPU0_SA_DQS_DP<0>")
	)
	(segment
		(start 306.402486 -302.848518)
		(end 304.709068 -304.541936)
		(width 0.18288)
		(layer "In6.Cu")
		(net "M_D_CPU0_SA_DQS_DP<0>")
	)
	(segment
		(start 279.618694 -314.191396)
		(end 279.324308 -313.89701)
		(width 0.18288)
		(layer "In6.Cu")
		(net "M_D_CPU0_SA_DQS_DP<0>")
	)
	(segment
		(start 282.992068 -314.744608)
		(end 282.293314 -314.045854)
		(width 0.18288)
		(layer "In6.Cu")
		(net "M_D_CPU0_SA_DQS_DP<0>")
	)
	(segment
		(start 332.658212 -280.07564)
		(end 332.658212 -280.63317)
		(width 0.088646)
		(layer "In6.Cu")
		(net "M_D_CPU0_SA_DQS_DP<0>")
	)
	(segment
		(start 338.170012 -275.8948)
		(end 338.170012 -275.904706)
		(width 0.088646)
		(layer "In6.Cu")
		(net "M_D_CPU0_SA_DQS_DP<0>")
	)
	(segment
		(start 294.182038 -309.650892)
		(end 293.715948 -310.116982)
		(width 0.18288)
		(layer "In6.Cu")
		(net "M_D_CPU0_SA_DQS_DP<0>")
	)
	(segment
		(start 268.64945 -313.341766)
		(end 268.37132 -313.063636)
		(width 0.18288)
		(layer "In6.Cu")
		(net "M_D_CPU0_SA_DQS_DP<0>")
	)
	(segment
		(start 315.818012 -298.628816)
		(end 314.997592 -299.449236)
		(width 0.18288)
		(layer "In6.Cu")
		(net "M_D_CPU0_SA_DQS_DP<0>")
	)
	(segment
		(start 294.415464 -309.650892)
		(end 294.182038 -309.650892)
		(width 0.18288)
		(layer "In6.Cu")
		(net "M_D_CPU0_SA_DQS_DP<0>")
	)
	(segment
		(start 332.39075 -280.900632)
		(end 332.077822 -280.900632)
		(width 0.088646)
		(layer "In6.Cu")
		(net "M_D_CPU0_SA_DQS_DP<0>")
	)
	(segment
		(start 300.930056 -306.80152)
		(end 300.18101 -307.111908)
		(width 0.18288)
		(layer "In6.Cu")
		(net "M_D_CPU0_SA_DQS_DP<0>")
	)
	(segment
		(start 337.887564 -276.384258)
		(end 337.878674 -276.389338)
		(width 0.088646)
		(layer "In6.Cu")
		(net "M_D_CPU0_SA_DQS_DP<0>")
	)
	(segment
		(start 267.092176 -312.52668)
		(end 266.846304 -312.424826)
		(width 0.18288)
		(layer "In6.Cu")
		(net "M_D_CPU0_SA_DQS_DP<0>")
	)
	(segment
		(start 269.041626 -313.341766)
		(end 268.64945 -313.341766)
		(width 0.18288)
		(layer "In6.Cu")
		(net "M_D_CPU0_SA_DQS_DP<0>")
	)
	(segment
		(start 278.844248 -313.89701)
		(end 277.84044 -312.893202)
		(width 0.18288)
		(layer "In6.Cu")
		(net "M_D_CPU0_SA_DQS_DP<0>")
	)
	(segment
		(start 336.397092 -278.02078)
		(end 336.38236 -278.012144)
		(width 0.088646)
		(layer "In6.Cu")
		(net "M_D_CPU0_SA_DQS_DP<0>")
	)
	(segment
		(start 302.113442 -305.618134)
		(end 300.930056 -306.80152)
		(width 0.18288)
		(layer "In6.Cu")
		(net "M_D_CPU0_SA_DQS_DP<0>")
	)
	(segment
		(start 284.116018 -315.041788)
		(end 283.718762 -315.041788)
		(width 0.18288)
		(layer "In6.Cu")
		(net "M_D_CPU0_SA_DQS_DP<0>")
	)
	(segment
		(start 337.409536 -277.202646)
		(end 337.408774 -277.203154)
		(width 0.088646)
		(layer "In6.Cu")
		(net "M_D_CPU0_SA_DQS_DP<0>")
	)
	(segment
		(start 308.48554 -300.900084)
		(end 307.759608 -301.20082)
		(width 0.18288)
		(layer "In6.Cu")
		(net "M_D_CPU0_SA_DQS_DP<0>")
	)
	(segment
		(start 313.657742 -299.499528)
		(end 312.785506 -299.499528)
		(width 0.18288)
		(layer "In6.Cu")
		(net "M_D_CPU0_SA_DQS_DP<0>")
	)
	(segment
		(start 342.681814 -275.449792)
		(end 342.326214 -275.449792)
		(width 0.088646)
		(layer "In6.Cu")
		(net "M_D_CPU0_SA_DQS_DP<0>")
	)
	(segment
		(start 295.826434 -309.662068)
		(end 295.464484 -309.662068)
		(width 0.18288)
		(layer "In6.Cu")
		(net "M_D_CPU0_SA_DQS_DP<0>")
	)
	(arc
		(start 343.613994 -275.10613)
		(mid 343.571464 -275.118897)
		(end 343.52992 -275.134578)
		(width 0.088646)
		(layer "In6.Cu")
		(net "M_D_CPU0_SA_DQS_DP<0>")
	)
	(arc
		(start 336.38236 -278.012144)
		(mid 336.195162 -277.962001)
		(end 336.007964 -278.012144)
		(width 0.088646)
		(layer "In6.Cu")
		(net "M_D_CPU0_SA_DQS_DP<0>")
	)
	(arc
		(start 335.068164 -278.012144)
		(mid 334.793965 -278.087979)
		(end 334.517492 -278.02078)
		(width 0.088646)
		(layer "In6.Cu")
		(net "M_D_CPU0_SA_DQS_DP<0>")
	)
	(arc
		(start 337.230212 -277.522432)
		(mid 337.156359 -277.802078)
		(end 336.95386 -278.008588)
		(width 0.088646)
		(layer "In6.Cu")
		(net "M_D_CPU0_SA_DQS_DP<0>")
	)
	(arc
		(start 338.170012 -275.904706)
		(mid 338.091901 -276.181655)
		(end 337.887564 -276.384258)
		(width 0.088646)
		(layer "In6.Cu")
		(net "M_D_CPU0_SA_DQS_DP<0>")
	)
	(arc
		(start 340.237064 -275.570188)
		(mid 339.954362 -275.645964)
		(end 339.67166 -275.570188)
		(width 0.088646)
		(layer "In6.Cu")
		(net "M_D_CPU0_SA_DQS_DP<0>")
	)
	(arc
		(start 335.44256 -278.012144)
		(mid 335.255362 -277.962001)
		(end 335.068164 -278.012144)
		(width 0.088646)
		(layer "In6.Cu")
		(net "M_D_CPU0_SA_DQS_DP<0>")
	)
	(arc
		(start 338.348574 -275.575522)
		(mid 338.21766 -275.711882)
		(end 338.170012 -275.8948)
		(width 0.088646)
		(layer "In6.Cu")
		(net "M_D_CPU0_SA_DQS_DP<0>")
	)
	(arc
		(start 334.50276 -278.012144)
		(mid 334.315562 -277.962001)
		(end 334.128364 -278.012144)
		(width 0.088646)
		(layer "In6.Cu")
		(net "M_D_CPU0_SA_DQS_DP<0>")
	)
	(arc
		(start 337.878674 -276.389338)
		(mid 337.74776 -276.525698)
		(end 337.700112 -276.708616)
		(width 0.088646)
		(layer "In6.Cu")
		(net "M_D_CPU0_SA_DQS_DP<0>")
	)
	(arc
		(start 343.229438 -275.258784)
		(mid 343.189083 -275.276979)
		(end 343.149936 -275.297646)
		(width 0.088646)
		(layer "In6.Cu")
		(net "M_D_CPU0_SA_DQS_DP<0>")
	)
	(arc
		(start 334.128364 -278.012144)
		(mid 334.087434 -278.039177)
		(end 334.050386 -278.071326)
		(width 0.088646)
		(layer "In6.Cu")
		(net "M_D_CPU0_SA_DQS_DP<0>")
	)
	(arc
		(start 336.007964 -278.012144)
		(mid 335.733765 -278.087979)
		(end 335.457292 -278.02078)
		(width 0.088646)
		(layer "In6.Cu")
		(net "M_D_CPU0_SA_DQS_DP<0>")
	)
	(arc
		(start 343.713816 -275.08073)
		(mid 343.663887 -275.093358)
		(end 343.613994 -275.10613)
		(width 0.088646)
		(layer "In6.Cu")
		(net "M_D_CPU0_SA_DQS_DP<0>")
	)
	(arc
		(start 338.73186 -275.570188)
		(mid 338.544662 -275.520045)
		(end 338.357464 -275.570188)
		(width 0.088646)
		(layer "In6.Cu")
		(net "M_D_CPU0_SA_DQS_DP<0>")
	)
	(arc
		(start 341.162132 -275.579078)
		(mid 340.885691 -275.646244)
		(end 340.61146 -275.570442)
		(width 0.088646)
		(layer "In6.Cu")
		(net "M_D_CPU0_SA_DQS_DP<0>")
	)
	(arc
		(start 337.700112 -276.718522)
		(mid 337.622001 -276.995471)
		(end 337.417664 -277.198074)
		(width 0.088646)
		(layer "In6.Cu")
		(net "M_D_CPU0_SA_DQS_DP<0>")
	)
	(arc
		(start 339.282532 -275.578824)
		(mid 339.006057 -275.646144)
		(end 338.73186 -275.570188)
		(width 0.088646)
		(layer "In6.Cu")
		(net "M_D_CPU0_SA_DQS_DP<0>")
	)
	(arc
		(start 342.102694 -275.57857)
		(mid 341.826029 -275.646041)
		(end 341.551514 -275.570188)
		(width 0.088646)
		(layer "In6.Cu")
		(net "M_D_CPU0_SA_DQS_DP<0>")
	)
	(arc
		(start 341.55126 -275.570442)
		(mid 341.364062 -275.520299)
		(end 341.176864 -275.570442)
		(width 0.088646)
		(layer "In6.Cu")
		(net "M_D_CPU0_SA_DQS_DP<0>")
	)
	(arc
		(start 337.408774 -277.203154)
		(mid 337.27786 -277.339514)
		(end 337.230212 -277.522432)
		(width 0.088646)
		(layer "In6.Cu")
		(net "M_D_CPU0_SA_DQS_DP<0>")
	)
	(arc
		(start 340.61146 -275.570188)
		(mid 340.424262 -275.520045)
		(end 340.237064 -275.570188)
		(width 0.088646)
		(layer "In6.Cu")
		(net "M_D_CPU0_SA_DQS_DP<0>")
	)
	(arc
		(start 339.67166 -275.570188)
		(mid 339.484462 -275.520045)
		(end 339.297264 -275.570188)
		(width 0.088646)
		(layer "In6.Cu")
		(net "M_D_CPU0_SA_DQS_DP<0>")
	)
	(arc
		(start 342.94826 -275.412454)
		(mid 342.849418 -275.449964)
		(end 342.74379 -275.45411)
		(width 0.088646)
		(layer "In6.Cu")
		(net "M_D_CPU0_SA_DQS_DP<0>")
	)
	(arc
		(start 336.947764 -278.012144)
		(mid 336.673565 -278.087979)
		(end 336.397092 -278.02078)
		(width 0.088646)
		(layer "In6.Cu")
		(net "M_D_CPU0_SA_DQS_DP<0>")
	)
	(segment
		(start 262.048752 -273.983196)
		(end 261.808976 -273.983196)
		(width 0.20066)
		(layer "F.Cu")
		(net "M_D_CPU0_SA_DQS_DN<9>")
	)
	(segment
		(start 261.386574 -274.405598)
		(end 260.913372 -274.405598)
		(width 0.20066)
		(layer "F.Cu")
		(net "M_D_CPU0_SA_DQS_DN<9>")
	)
	(segment
		(start 268.829282 -274.66671)
		(end 267.724382 -274.66671)
		(width 0.20066)
		(layer "F.Cu")
		(net "M_D_CPU0_SA_DQS_DN<9>")
	)
	(segment
		(start 266.269216 -274.405598)
		(end 265.6332 -273.980656)
		(width 0.20066)
		(layer "F.Cu")
		(net "M_D_CPU0_SA_DQS_DN<9>")
	)
	(segment
		(start 265.6332 -273.980656)
		(end 265.228578 -273.980656)
		(width 0.20066)
		(layer "F.Cu")
		(net "M_D_CPU0_SA_DQS_DN<9>")
	)
	(segment
		(start 266.972796 -274.405598)
		(end 266.269216 -274.405598)
		(width 0.20066)
		(layer "F.Cu")
		(net "M_D_CPU0_SA_DQS_DN<9>")
	)
	(segment
		(start 262.316976 -274.25142)
		(end 262.048752 -273.983196)
		(width 0.20066)
		(layer "F.Cu")
		(net "M_D_CPU0_SA_DQS_DN<9>")
	)
	(segment
		(start 267.233908 -274.66671)
		(end 266.972796 -274.405598)
		(width 0.20066)
		(layer "F.Cu")
		(net "M_D_CPU0_SA_DQS_DN<9>")
	)
	(segment
		(start 262.74776 -274.241768)
		(end 262.510016 -274.241768)
		(width 0.101854)
		(layer "F.Cu")
		(net "M_D_CPU0_SA_DQS_DN<9>")
	)
	(segment
		(start 347.942916 -262.336534)
		(end 347.942916 -262.87222)
		(width 0.20066)
		(layer "F.Cu")
		(net "M_D_CPU0_SA_DQS_DN<9>")
	)
	(segment
		(start 264.967466 -274.241768)
		(end 264.82548 -274.241768)
		(width 0.20066)
		(layer "F.Cu")
		(net "M_D_CPU0_SA_DQS_DN<9>")
	)
	(segment
		(start 265.228578 -273.980656)
		(end 264.967466 -274.241768)
		(width 0.20066)
		(layer "F.Cu")
		(net "M_D_CPU0_SA_DQS_DN<9>")
	)
	(segment
		(start 260.913372 -274.405598)
		(end 260.65226 -274.66671)
		(width 0.20066)
		(layer "F.Cu")
		(net "M_D_CPU0_SA_DQS_DN<9>")
	)
	(segment
		(start 347.942916 -262.87222)
		(end 347.942662 -262.872474)
		(width 0.20066)
		(layer "F.Cu")
		(net "M_D_CPU0_SA_DQS_DN<9>")
	)
	(segment
		(start 261.808976 -273.983196)
		(end 261.386574 -274.405598)
		(width 0.20066)
		(layer "F.Cu")
		(net "M_D_CPU0_SA_DQS_DN<9>")
	)
	(segment
		(start 267.724382 -274.66671)
		(end 267.233908 -274.66671)
		(width 0.20066)
		(layer "F.Cu")
		(net "M_D_CPU0_SA_DQS_DN<9>")
	)
	(segment
		(start 260.65226 -274.66671)
		(end 260.180582 -274.66671)
		(width 0.20066)
		(layer "F.Cu")
		(net "M_D_CPU0_SA_DQS_DN<9>")
	)
	(segment
		(start 262.510016 -274.241768)
		(end 262.500364 -274.25142)
		(width 0.101854)
		(layer "F.Cu")
		(net "M_D_CPU0_SA_DQS_DN<9>")
	)
	(segment
		(start 264.82548 -274.241768)
		(end 262.74776 -274.241768)
		(width 0.1016)
		(layer "F.Cu")
		(net "M_D_CPU0_SA_DQS_DN<9>")
	)
	(segment
		(start 262.500364 -274.25142)
		(end 262.316976 -274.25142)
		(width 0.20066)
		(layer "F.Cu")
		(net "M_D_CPU0_SA_DQS_DN<9>")
	)
	(segment
		(start 285.490412 -271.67586)
		(end 285.249366 -271.434814)
		(width 0.18288)
		(layer "In11.Cu")
		(net "M_D_CPU0_SA_DQS_DN<9>")
	)
	(segment
		(start 337.794346 -262.549386)
		(end 337.792314 -262.548116)
		(width 0.088646)
		(layer "In11.Cu")
		(net "M_D_CPU0_SA_DQS_DN<9>")
	)
	(segment
		(start 337.792314 -262.548116)
		(end 337.791806 -262.547862)
		(width 0.088646)
		(layer "In11.Cu")
		(net "M_D_CPU0_SA_DQS_DN<9>")
	)
	(segment
		(start 346.256356 -262.551418)
		(end 346.244672 -262.544814)
		(width 0.088646)
		(layer "In11.Cu")
		(net "M_D_CPU0_SA_DQS_DN<9>")
	)
	(segment
		(start 273.062192 -273.381216)
		(end 271.987518 -273.381216)
		(width 0.18288)
		(layer "In11.Cu")
		(net "M_D_CPU0_SA_DQS_DN<9>")
	)
	(segment
		(start 298.537884 -271.416272)
		(end 297.83659 -271.416272)
		(width 0.18288)
		(layer "In11.Cu")
		(net "M_D_CPU0_SA_DQS_DN<9>")
	)
	(segment
		(start 331.03693 -262.99922)
		(end 330.97724 -263.05891)
		(width 0.088646)
		(layer "In11.Cu")
		(net "M_D_CPU0_SA_DQS_DN<9>")
	)
	(segment
		(start 307.242718 -271.279366)
		(end 306.79644 -270.833088)
		(width 0.18288)
		(layer "In11.Cu")
		(net "M_D_CPU0_SA_DQS_DN<9>")
	)
	(segment
		(start 345.316556 -262.551418)
		(end 345.304872 -262.544814)
		(width 0.088646)
		(layer "In11.Cu")
		(net "M_D_CPU0_SA_DQS_DN<9>")
	)
	(segment
		(start 314.712858 -270.78686)
		(end 314.164218 -270.78686)
		(width 0.18288)
		(layer "In11.Cu")
		(net "M_D_CPU0_SA_DQS_DN<9>")
	)
	(segment
		(start 295.093898 -272.542762)
		(end 294.713914 -272.542762)
		(width 0.18288)
		(layer "In11.Cu")
		(net "M_D_CPU0_SA_DQS_DN<9>")
	)
	(segment
		(start 347.94825 -262.878062)
		(end 348.250002 -262.878062)
		(width 0.088646)
		(layer "In11.Cu")
		(net "M_D_CPU0_SA_DQS_DN<9>")
	)
	(segment
		(start 279.624282 -272.54073)
		(end 279.339294 -272.255742)
		(width 0.18288)
		(layer "In11.Cu")
		(net "M_D_CPU0_SA_DQS_DN<9>")
	)
	(segment
		(start 273.910298 -272.53311)
		(end 273.062192 -273.381216)
		(width 0.18288)
		(layer "In11.Cu")
		(net "M_D_CPU0_SA_DQS_DN<9>")
	)
	(segment
		(start 293.993062 -272.262092)
		(end 293.325042 -272.930112)
		(width 0.18288)
		(layer "In11.Cu")
		(net "M_D_CPU0_SA_DQS_DN<9>")
	)
	(segment
		(start 309.380128 -271.279366)
		(end 307.242718 -271.279366)
		(width 0.18288)
		(layer "In11.Cu")
		(net "M_D_CPU0_SA_DQS_DN<9>")
	)
	(segment
		(start 330.97724 -263.05891)
		(end 323.128894 -263.05891)
		(width 0.18288)
		(layer "In11.Cu")
		(net "M_D_CPU0_SA_DQS_DN<9>")
	)
	(segment
		(start 269.409164 -274.377912)
		(end 269.11808 -274.377912)
		(width 0.18288)
		(layer "In11.Cu")
		(net "M_D_CPU0_SA_DQS_DN<9>")
	)
	(segment
		(start 312.605166 -270.6624)
		(end 311.343294 -270.6624)
		(width 0.18288)
		(layer "In11.Cu")
		(net "M_D_CPU0_SA_DQS_DN<9>")
	)
	(segment
		(start 300.722538 -271.681194)
		(end 300.457616 -271.416272)
		(width 0.18288)
		(layer "In11.Cu")
		(net "M_D_CPU0_SA_DQS_DN<9>")
	)
	(segment
		(start 297.381168 -271.871694)
		(end 296.411142 -272.273014)
		(width 0.18288)
		(layer "In11.Cu")
		(net "M_D_CPU0_SA_DQS_DN<9>")
	)
	(segment
		(start 336.852768 -262.547862)
		(end 336.85226 -262.548116)
		(width 0.088646)
		(layer "In11.Cu")
		(net "M_D_CPU0_SA_DQS_DN<9>")
	)
	(segment
		(start 311.343294 -270.6624)
		(end 310.726328 -271.279366)
		(width 0.18288)
		(layer "In11.Cu")
		(net "M_D_CPU0_SA_DQS_DN<9>")
	)
	(segment
		(start 314.164218 -270.78686)
		(end 314.039758 -270.6624)
		(width 0.18288)
		(layer "In11.Cu")
		(net "M_D_CPU0_SA_DQS_DN<9>")
	)
	(segment
		(start 313.402726 -270.6624)
		(end 313.278266 -270.78686)
		(width 0.18288)
		(layer "In11.Cu")
		(net "M_D_CPU0_SA_DQS_DN<9>")
	)
	(segment
		(start 348.250002 -262.878062)
		(end 348.312994 -262.81507)
		(width 0.088646)
		(layer "In11.Cu")
		(net "M_D_CPU0_SA_DQS_DN<9>")
	)
	(segment
		(start 304.155348 -270.833088)
		(end 303.307242 -271.681194)
		(width 0.18288)
		(layer "In11.Cu")
		(net "M_D_CPU0_SA_DQS_DN<9>")
	)
	(segment
		(start 278.972518 -272.255742)
		(end 278.315674 -272.912586)
		(width 0.18288)
		(layer "In11.Cu")
		(net "M_D_CPU0_SA_DQS_DN<9>")
	)
	(segment
		(start 337.791806 -262.547862)
		(end 337.791806 -262.547608)
		(width 0.088646)
		(layer "In11.Cu")
		(net "M_D_CPU0_SA_DQS_DN<9>")
	)
	(segment
		(start 315.525404 -270.6624)
		(end 314.837318 -270.6624)
		(width 0.18288)
		(layer "In11.Cu")
		(net "M_D_CPU0_SA_DQS_DN<9>")
	)
	(segment
		(start 331.65415 -262.68426)
		(end 331.33919 -262.99922)
		(width 0.088646)
		(layer "In11.Cu")
		(net "M_D_CPU0_SA_DQS_DN<9>")
	)
	(segment
		(start 292.3032 -272.930112)
		(end 291.722556 -272.349468)
		(width 0.18288)
		(layer "In11.Cu")
		(net "M_D_CPU0_SA_DQS_DN<9>")
	)
	(segment
		(start 295.363646 -272.273014)
		(end 295.093898 -272.542762)
		(width 0.18288)
		(layer "In11.Cu")
		(net "M_D_CPU0_SA_DQS_DN<9>")
	)
	(segment
		(start 278.315674 -272.912586)
		(end 277.09114 -272.912586)
		(width 0.18288)
		(layer "In11.Cu")
		(net "M_D_CPU0_SA_DQS_DN<9>")
	)
	(segment
		(start 299.465492 -271.416272)
		(end 299.190156 -271.691608)
		(width 0.18288)
		(layer "In11.Cu")
		(net "M_D_CPU0_SA_DQS_DN<9>")
	)
	(segment
		(start 310.726328 -271.279366)
		(end 310.177688 -271.279366)
		(width 0.18288)
		(layer "In11.Cu")
		(net "M_D_CPU0_SA_DQS_DN<9>")
	)
	(segment
		(start 294.713914 -272.542762)
		(end 294.433244 -272.262092)
		(width 0.18288)
		(layer "In11.Cu")
		(net "M_D_CPU0_SA_DQS_DN<9>")
	)
	(segment
		(start 294.433244 -272.262092)
		(end 293.993062 -272.262092)
		(width 0.18288)
		(layer "In11.Cu")
		(net "M_D_CPU0_SA_DQS_DN<9>")
	)
	(segment
		(start 297.83659 -271.416272)
		(end 297.381168 -271.871694)
		(width 0.18288)
		(layer "In11.Cu")
		(net "M_D_CPU0_SA_DQS_DN<9>")
	)
	(segment
		(start 332.18882 -262.593836)
		(end 332.095094 -262.567674)
		(width 0.088646)
		(layer "In11.Cu")
		(net "M_D_CPU0_SA_DQS_DN<9>")
	)
	(segment
		(start 323.128894 -263.05891)
		(end 315.525404 -270.6624)
		(width 0.18288)
		(layer "In11.Cu")
		(net "M_D_CPU0_SA_DQS_DN<9>")
	)
	(segment
		(start 277.09114 -272.912586)
		(end 276.711664 -272.53311)
		(width 0.18288)
		(layer "In11.Cu")
		(net "M_D_CPU0_SA_DQS_DN<9>")
	)
	(segment
		(start 298.81322 -271.691608)
		(end 298.537884 -271.416272)
		(width 0.18288)
		(layer "In11.Cu")
		(net "M_D_CPU0_SA_DQS_DN<9>")
	)
	(segment
		(start 339.677756 -262.551418)
		(end 339.666072 -262.544814)
		(width 0.088646)
		(layer "In11.Cu")
		(net "M_D_CPU0_SA_DQS_DN<9>")
	)
	(segment
		(start 269.11808 -274.377912)
		(end 268.829282 -274.66671)
		(width 0.18288)
		(layer "In11.Cu")
		(net "M_D_CPU0_SA_DQS_DN<9>")
	)
	(segment
		(start 343.436956 -262.551418)
		(end 343.425272 -262.544814)
		(width 0.088646)
		(layer "In11.Cu")
		(net "M_D_CPU0_SA_DQS_DN<9>")
	)
	(segment
		(start 280.260806 -272.284698)
		(end 280.004774 -272.54073)
		(width 0.18288)
		(layer "In11.Cu")
		(net "M_D_CPU0_SA_DQS_DN<9>")
	)
	(segment
		(start 282.78328 -271.481296)
		(end 281.979878 -272.284698)
		(width 0.18288)
		(layer "In11.Cu")
		(net "M_D_CPU0_SA_DQS_DN<9>")
	)
	(segment
		(start 283.72308 -271.689068)
		(end 283.515308 -271.481296)
		(width 0.18288)
		(layer "In11.Cu")
		(net "M_D_CPU0_SA_DQS_DN<9>")
	)
	(segment
		(start 291.722556 -272.349468)
		(end 288.501328 -272.349468)
		(width 0.18288)
		(layer "In11.Cu")
		(net "M_D_CPU0_SA_DQS_DN<9>")
	)
	(segment
		(start 303.307242 -271.681194)
		(end 300.722538 -271.681194)
		(width 0.18288)
		(layer "In11.Cu")
		(net "M_D_CPU0_SA_DQS_DN<9>")
	)
	(segment
		(start 314.837318 -270.6624)
		(end 314.712858 -270.78686)
		(width 0.18288)
		(layer "In11.Cu")
		(net "M_D_CPU0_SA_DQS_DN<9>")
	)
	(segment
		(start 300.457616 -271.416272)
		(end 299.465492 -271.416272)
		(width 0.18288)
		(layer "In11.Cu")
		(net "M_D_CPU0_SA_DQS_DN<9>")
	)
	(segment
		(start 306.79644 -270.833088)
		(end 304.155348 -270.833088)
		(width 0.18288)
		(layer "In11.Cu")
		(net "M_D_CPU0_SA_DQS_DN<9>")
	)
	(segment
		(start 287.82772 -271.67586)
		(end 285.490412 -271.67586)
		(width 0.18288)
		(layer "In11.Cu")
		(net "M_D_CPU0_SA_DQS_DN<9>")
	)
	(segment
		(start 293.325042 -272.930112)
		(end 292.3032 -272.930112)
		(width 0.18288)
		(layer "In11.Cu")
		(net "M_D_CPU0_SA_DQS_DN<9>")
	)
	(segment
		(start 299.190156 -271.691608)
		(end 298.81322 -271.691608)
		(width 0.18288)
		(layer "In11.Cu")
		(net "M_D_CPU0_SA_DQS_DN<9>")
	)
	(segment
		(start 310.177688 -271.279366)
		(end 310.053228 -271.403826)
		(width 0.18288)
		(layer "In11.Cu")
		(net "M_D_CPU0_SA_DQS_DN<9>")
	)
	(segment
		(start 285.249366 -271.434814)
		(end 284.372558 -271.434814)
		(width 0.18288)
		(layer "In11.Cu")
		(net "M_D_CPU0_SA_DQS_DN<9>")
	)
	(segment
		(start 276.711664 -272.53311)
		(end 273.910298 -272.53311)
		(width 0.18288)
		(layer "In11.Cu")
		(net "M_D_CPU0_SA_DQS_DN<9>")
	)
	(segment
		(start 280.004774 -272.54073)
		(end 279.624282 -272.54073)
		(width 0.18288)
		(layer "In11.Cu")
		(net "M_D_CPU0_SA_DQS_DN<9>")
	)
	(segment
		(start 347.196156 -262.551418)
		(end 347.184472 -262.544814)
		(width 0.088646)
		(layer "In11.Cu")
		(net "M_D_CPU0_SA_DQS_DN<9>")
	)
	(segment
		(start 271.987518 -273.381216)
		(end 270.634968 -274.733766)
		(width 0.18288)
		(layer "In11.Cu")
		(net "M_D_CPU0_SA_DQS_DN<9>")
	)
	(segment
		(start 269.765018 -274.733766)
		(end 269.409164 -274.377912)
		(width 0.18288)
		(layer "In11.Cu")
		(net "M_D_CPU0_SA_DQS_DN<9>")
	)
	(segment
		(start 341.557356 -262.551418)
		(end 341.545672 -262.544814)
		(width 0.088646)
		(layer "In11.Cu")
		(net "M_D_CPU0_SA_DQS_DN<9>")
	)
	(segment
		(start 309.504588 -271.403826)
		(end 309.380128 -271.279366)
		(width 0.18288)
		(layer "In11.Cu")
		(net "M_D_CPU0_SA_DQS_DN<9>")
	)
	(segment
		(start 313.278266 -270.78686)
		(end 312.729626 -270.78686)
		(width 0.18288)
		(layer "In11.Cu")
		(net "M_D_CPU0_SA_DQS_DN<9>")
	)
	(segment
		(start 284.372558 -271.434814)
		(end 284.118304 -271.689068)
		(width 0.18288)
		(layer "In11.Cu")
		(net "M_D_CPU0_SA_DQS_DN<9>")
	)
	(segment
		(start 337.79587 -262.550148)
		(end 337.794346 -262.549386)
		(width 0.088646)
		(layer "In11.Cu")
		(net "M_D_CPU0_SA_DQS_DN<9>")
	)
	(segment
		(start 347.942662 -262.872474)
		(end 347.94825 -262.878062)
		(width 0.088646)
		(layer "In11.Cu")
		(net "M_D_CPU0_SA_DQS_DN<9>")
	)
	(segment
		(start 270.634968 -274.733766)
		(end 269.765018 -274.733766)
		(width 0.18288)
		(layer "In11.Cu")
		(net "M_D_CPU0_SA_DQS_DN<9>")
	)
	(segment
		(start 331.33919 -262.99922)
		(end 331.03693 -262.99922)
		(width 0.088646)
		(layer "In11.Cu")
		(net "M_D_CPU0_SA_DQS_DN<9>")
	)
	(segment
		(start 279.339294 -272.255742)
		(end 278.972518 -272.255742)
		(width 0.18288)
		(layer "In11.Cu")
		(net "M_D_CPU0_SA_DQS_DN<9>")
	)
	(segment
		(start 314.039758 -270.6624)
		(end 313.402726 -270.6624)
		(width 0.18288)
		(layer "In11.Cu")
		(net "M_D_CPU0_SA_DQS_DN<9>")
	)
	(segment
		(start 296.411142 -272.273014)
		(end 295.363646 -272.273014)
		(width 0.18288)
		(layer "In11.Cu")
		(net "M_D_CPU0_SA_DQS_DN<9>")
	)
	(segment
		(start 344.376756 -262.551418)
		(end 344.365072 -262.544814)
		(width 0.088646)
		(layer "In11.Cu")
		(net "M_D_CPU0_SA_DQS_DN<9>")
	)
	(segment
		(start 338.737956 -262.551418)
		(end 338.726272 -262.544814)
		(width 0.088646)
		(layer "In11.Cu")
		(net "M_D_CPU0_SA_DQS_DN<9>")
	)
	(segment
		(start 284.118304 -271.689068)
		(end 283.72308 -271.689068)
		(width 0.18288)
		(layer "In11.Cu")
		(net "M_D_CPU0_SA_DQS_DN<9>")
	)
	(segment
		(start 340.617556 -262.551418)
		(end 340.605872 -262.544814)
		(width 0.088646)
		(layer "In11.Cu")
		(net "M_D_CPU0_SA_DQS_DN<9>")
	)
	(segment
		(start 283.515308 -271.481296)
		(end 282.78328 -271.481296)
		(width 0.18288)
		(layer "In11.Cu")
		(net "M_D_CPU0_SA_DQS_DN<9>")
	)
	(segment
		(start 342.497156 -262.551418)
		(end 342.485472 -262.544814)
		(width 0.088646)
		(layer "In11.Cu")
		(net "M_D_CPU0_SA_DQS_DN<9>")
	)
	(segment
		(start 312.729626 -270.78686)
		(end 312.605166 -270.6624)
		(width 0.18288)
		(layer "In11.Cu")
		(net "M_D_CPU0_SA_DQS_DN<9>")
	)
	(segment
		(start 281.979878 -272.284698)
		(end 280.260806 -272.284698)
		(width 0.18288)
		(layer "In11.Cu")
		(net "M_D_CPU0_SA_DQS_DN<9>")
	)
	(segment
		(start 288.501328 -272.349468)
		(end 287.82772 -271.67586)
		(width 0.18288)
		(layer "In11.Cu")
		(net "M_D_CPU0_SA_DQS_DN<9>")
	)
	(segment
		(start 310.053228 -271.403826)
		(end 309.504588 -271.403826)
		(width 0.18288)
		(layer "In11.Cu")
		(net "M_D_CPU0_SA_DQS_DN<9>")
	)
	(arc
		(start 341.176864 -262.548116)
		(mid 340.897661 -262.623756)
		(end 340.617556 -262.551418)
		(width 0.088646)
		(layer "In11.Cu")
		(net "M_D_CPU0_SA_DQS_DN<9>")
	)
	(arc
		(start 332.73492 -262.538464)
		(mid 332.467082 -262.617477)
		(end 332.18882 -262.593836)
		(width 0.088646)
		(layer "In11.Cu")
		(net "M_D_CPU0_SA_DQS_DN<9>")
	)
	(arc
		(start 338.357464 -262.548116)
		(mid 338.076953 -262.623762)
		(end 337.79587 -262.550148)
		(width 0.088646)
		(layer "In11.Cu")
		(net "M_D_CPU0_SA_DQS_DN<9>")
	)
	(arc
		(start 346.244672 -262.544814)
		(mid 346.059817 -262.497864)
		(end 345.875864 -262.548116)
		(width 0.088646)
		(layer "In11.Cu")
		(net "M_D_CPU0_SA_DQS_DN<9>")
	)
	(arc
		(start 340.605872 -262.544814)
		(mid 340.421017 -262.497864)
		(end 340.237064 -262.548116)
		(width 0.088646)
		(layer "In11.Cu")
		(net "M_D_CPU0_SA_DQS_DN<9>")
	)
	(arc
		(start 336.477864 -262.548116)
		(mid 336.195162 -262.623892)
		(end 335.91246 -262.548116)
		(width 0.088646)
		(layer "In11.Cu")
		(net "M_D_CPU0_SA_DQS_DN<9>")
	)
	(arc
		(start 344.936064 -262.548116)
		(mid 344.656861 -262.623756)
		(end 344.376756 -262.551418)
		(width 0.088646)
		(layer "In11.Cu")
		(net "M_D_CPU0_SA_DQS_DN<9>")
	)
	(arc
		(start 343.425272 -262.544814)
		(mid 343.240417 -262.497864)
		(end 343.056464 -262.548116)
		(width 0.088646)
		(layer "In11.Cu")
		(net "M_D_CPU0_SA_DQS_DN<9>")
	)
	(arc
		(start 332.095094 -262.567674)
		(mid 331.858896 -262.566432)
		(end 331.65415 -262.68426)
		(width 0.088646)
		(layer "In11.Cu")
		(net "M_D_CPU0_SA_DQS_DN<9>")
	)
	(arc
		(start 347.755464 -262.548116)
		(mid 347.476261 -262.623756)
		(end 347.196156 -262.551418)
		(width 0.088646)
		(layer "In11.Cu")
		(net "M_D_CPU0_SA_DQS_DN<9>")
	)
	(arc
		(start 345.875864 -262.548116)
		(mid 345.596661 -262.623756)
		(end 345.316556 -262.551418)
		(width 0.088646)
		(layer "In11.Cu")
		(net "M_D_CPU0_SA_DQS_DN<9>")
	)
	(arc
		(start 335.91246 -262.548116)
		(mid 335.725262 -262.497973)
		(end 335.538064 -262.548116)
		(width 0.088646)
		(layer "In11.Cu")
		(net "M_D_CPU0_SA_DQS_DN<9>")
	)
	(arc
		(start 342.485472 -262.544814)
		(mid 342.300617 -262.497864)
		(end 342.116664 -262.548116)
		(width 0.088646)
		(layer "In11.Cu")
		(net "M_D_CPU0_SA_DQS_DN<9>")
	)
	(arc
		(start 341.545672 -262.544814)
		(mid 341.360817 -262.497864)
		(end 341.176864 -262.548116)
		(width 0.088646)
		(layer "In11.Cu")
		(net "M_D_CPU0_SA_DQS_DN<9>")
	)
	(arc
		(start 334.97266 -262.548116)
		(mid 334.785462 -262.497973)
		(end 334.598264 -262.548116)
		(width 0.088646)
		(layer "In11.Cu")
		(net "M_D_CPU0_SA_DQS_DN<9>")
	)
	(arc
		(start 337.791806 -262.547608)
		(mid 337.604579 -262.49766)
		(end 337.41741 -262.547862)
		(width 0.088646)
		(layer "In11.Cu")
		(net "M_D_CPU0_SA_DQS_DN<9>")
	)
	(arc
		(start 336.85226 -262.548116)
		(mid 336.665062 -262.497973)
		(end 336.477864 -262.548116)
		(width 0.088646)
		(layer "In11.Cu")
		(net "M_D_CPU0_SA_DQS_DN<9>")
	)
	(arc
		(start 337.41741 -262.547862)
		(mid 337.135106 -262.623418)
		(end 336.852768 -262.547862)
		(width 0.088646)
		(layer "In11.Cu")
		(net "M_D_CPU0_SA_DQS_DN<9>")
	)
	(arc
		(start 333.658464 -262.548116)
		(mid 333.375762 -262.623892)
		(end 333.09306 -262.548116)
		(width 0.088646)
		(layer "In11.Cu")
		(net "M_D_CPU0_SA_DQS_DN<9>")
	)
	(arc
		(start 334.03286 -262.548116)
		(mid 333.845662 -262.497973)
		(end 333.658464 -262.548116)
		(width 0.088646)
		(layer "In11.Cu")
		(net "M_D_CPU0_SA_DQS_DN<9>")
	)
	(arc
		(start 333.09306 -262.548116)
		(mid 332.915216 -262.497728)
		(end 332.73492 -262.538464)
		(width 0.088646)
		(layer "In11.Cu")
		(net "M_D_CPU0_SA_DQS_DN<9>")
	)
	(arc
		(start 346.815664 -262.548116)
		(mid 346.536461 -262.623756)
		(end 346.256356 -262.551418)
		(width 0.088646)
		(layer "In11.Cu")
		(net "M_D_CPU0_SA_DQS_DN<9>")
	)
	(arc
		(start 338.726272 -262.544814)
		(mid 338.541417 -262.497864)
		(end 338.357464 -262.548116)
		(width 0.088646)
		(layer "In11.Cu")
		(net "M_D_CPU0_SA_DQS_DN<9>")
	)
	(arc
		(start 347.184472 -262.544814)
		(mid 346.999617 -262.497864)
		(end 346.815664 -262.548116)
		(width 0.088646)
		(layer "In11.Cu")
		(net "M_D_CPU0_SA_DQS_DN<9>")
	)
	(arc
		(start 343.996264 -262.548116)
		(mid 343.717061 -262.623756)
		(end 343.436956 -262.551418)
		(width 0.088646)
		(layer "In11.Cu")
		(net "M_D_CPU0_SA_DQS_DN<9>")
	)
	(arc
		(start 335.538064 -262.548116)
		(mid 335.255362 -262.623892)
		(end 334.97266 -262.548116)
		(width 0.088646)
		(layer "In11.Cu")
		(net "M_D_CPU0_SA_DQS_DN<9>")
	)
	(arc
		(start 348.312994 -262.81507)
		(mid 348.104612 -262.534676)
		(end 347.755464 -262.548116)
		(width 0.088646)
		(layer "In11.Cu")
		(net "M_D_CPU0_SA_DQS_DN<9>")
	)
	(arc
		(start 342.116664 -262.548116)
		(mid 341.837461 -262.623756)
		(end 341.557356 -262.551418)
		(width 0.088646)
		(layer "In11.Cu")
		(net "M_D_CPU0_SA_DQS_DN<9>")
	)
	(arc
		(start 334.598264 -262.548116)
		(mid 334.315562 -262.623892)
		(end 334.03286 -262.548116)
		(width 0.088646)
		(layer "In11.Cu")
		(net "M_D_CPU0_SA_DQS_DN<9>")
	)
	(arc
		(start 339.666072 -262.544814)
		(mid 339.481217 -262.497864)
		(end 339.297264 -262.548116)
		(width 0.088646)
		(layer "In11.Cu")
		(net "M_D_CPU0_SA_DQS_DN<9>")
	)
	(arc
		(start 339.297264 -262.548116)
		(mid 339.018061 -262.623756)
		(end 338.737956 -262.551418)
		(width 0.088646)
		(layer "In11.Cu")
		(net "M_D_CPU0_SA_DQS_DN<9>")
	)
	(arc
		(start 340.237064 -262.548116)
		(mid 339.957861 -262.623756)
		(end 339.677756 -262.551418)
		(width 0.088646)
		(layer "In11.Cu")
		(net "M_D_CPU0_SA_DQS_DN<9>")
	)
	(arc
		(start 345.304872 -262.544814)
		(mid 345.120017 -262.497864)
		(end 344.936064 -262.548116)
		(width 0.088646)
		(layer "In11.Cu")
		(net "M_D_CPU0_SA_DQS_DN<9>")
	)
	(arc
		(start 343.056464 -262.548116)
		(mid 342.777261 -262.623756)
		(end 342.497156 -262.551418)
		(width 0.088646)
		(layer "In11.Cu")
		(net "M_D_CPU0_SA_DQS_DN<9>")
	)
	(arc
		(start 344.365072 -262.544814)
		(mid 344.180217 -262.497864)
		(end 343.996264 -262.548116)
		(width 0.088646)
		(layer "In11.Cu")
		(net "M_D_CPU0_SA_DQS_DN<9>")
	)
	(segment
		(start 262.316976 -283.601414)
		(end 262.048752 -283.33319)
		(width 0.20066)
		(layer "F.Cu")
		(net "M_D_CPU0_SA_DQS_DN<8>")
	)
	(segment
		(start 260.65226 -284.016704)
		(end 260.180582 -284.016704)
		(width 0.20066)
		(layer "F.Cu")
		(net "M_D_CPU0_SA_DQS_DN<8>")
	)
	(segment
		(start 261.808976 -283.33319)
		(end 261.386574 -283.755592)
		(width 0.20066)
		(layer "F.Cu")
		(net "M_D_CPU0_SA_DQS_DN<8>")
	)
	(segment
		(start 264.967466 -283.591762)
		(end 264.825226 -283.591762)
		(width 0.20066)
		(layer "F.Cu")
		(net "M_D_CPU0_SA_DQS_DN<8>")
	)
	(segment
		(start 347.942662 -267.220192)
		(end 347.942662 -267.755878)
		(width 0.20066)
		(layer "F.Cu")
		(net "M_D_CPU0_SA_DQS_DN<8>")
	)
	(segment
		(start 265.228578 -283.33065)
		(end 264.967466 -283.591762)
		(width 0.20066)
		(layer "F.Cu")
		(net "M_D_CPU0_SA_DQS_DN<8>")
	)
	(segment
		(start 264.825226 -283.591762)
		(end 262.74776 -283.591762)
		(width 0.1016)
		(layer "F.Cu")
		(net "M_D_CPU0_SA_DQS_DN<8>")
	)
	(segment
		(start 260.913372 -283.755592)
		(end 260.65226 -284.016704)
		(width 0.20066)
		(layer "F.Cu")
		(net "M_D_CPU0_SA_DQS_DN<8>")
	)
	(segment
		(start 262.509762 -283.591762)
		(end 262.50011 -283.601414)
		(width 0.101854)
		(layer "F.Cu")
		(net "M_D_CPU0_SA_DQS_DN<8>")
	)
	(segment
		(start 268.829282 -284.016704)
		(end 267.724382 -284.016704)
		(width 0.20066)
		(layer "F.Cu")
		(net "M_D_CPU0_SA_DQS_DN<8>")
	)
	(segment
		(start 262.048752 -283.33319)
		(end 261.808976 -283.33319)
		(width 0.20066)
		(layer "F.Cu")
		(net "M_D_CPU0_SA_DQS_DN<8>")
	)
	(segment
		(start 267.233908 -284.016704)
		(end 266.972796 -283.755592)
		(width 0.20066)
		(layer "F.Cu")
		(net "M_D_CPU0_SA_DQS_DN<8>")
	)
	(segment
		(start 266.972796 -283.755592)
		(end 266.269216 -283.755592)
		(width 0.20066)
		(layer "F.Cu")
		(net "M_D_CPU0_SA_DQS_DN<8>")
	)
	(segment
		(start 265.6332 -283.33065)
		(end 265.228578 -283.33065)
		(width 0.20066)
		(layer "F.Cu")
		(net "M_D_CPU0_SA_DQS_DN<8>")
	)
	(segment
		(start 266.269216 -283.755592)
		(end 265.6332 -283.33065)
		(width 0.20066)
		(layer "F.Cu")
		(net "M_D_CPU0_SA_DQS_DN<8>")
	)
	(segment
		(start 267.724382 -284.016704)
		(end 267.233908 -284.016704)
		(width 0.20066)
		(layer "F.Cu")
		(net "M_D_CPU0_SA_DQS_DN<8>")
	)
	(segment
		(start 347.942916 -267.219938)
		(end 347.942662 -267.220192)
		(width 0.20066)
		(layer "F.Cu")
		(net "M_D_CPU0_SA_DQS_DN<8>")
	)
	(segment
		(start 261.386574 -283.755592)
		(end 260.913372 -283.755592)
		(width 0.20066)
		(layer "F.Cu")
		(net "M_D_CPU0_SA_DQS_DN<8>")
	)
	(segment
		(start 262.74776 -283.591762)
		(end 262.509762 -283.591762)
		(width 0.101854)
		(layer "F.Cu")
		(net "M_D_CPU0_SA_DQS_DN<8>")
	)
	(segment
		(start 262.50011 -283.601414)
		(end 262.316976 -283.601414)
		(width 0.20066)
		(layer "F.Cu")
		(net "M_D_CPU0_SA_DQS_DN<8>")
	)
	(segment
		(start 331.788008 -267.831316)
		(end 331.788008 -268.387322)
		(width 0.088646)
		(layer "In11.Cu")
		(net "M_D_CPU0_SA_DQS_DN<8>")
	)
	(segment
		(start 314.773818 -279.991312)
		(end 313.415172 -279.991312)
		(width 0.18288)
		(layer "In11.Cu")
		(net "M_D_CPU0_SA_DQS_DN<8>")
	)
	(segment
		(start 269.113254 -283.732732)
		(end 268.829282 -284.016704)
		(width 0.18288)
		(layer "In11.Cu")
		(net "M_D_CPU0_SA_DQS_DN<8>")
	)
	(segment
		(start 292.311328 -282.732226)
		(end 291.90823 -283.135324)
		(width 0.18288)
		(layer "In11.Cu")
		(net "M_D_CPU0_SA_DQS_DN<8>")
	)
	(segment
		(start 348.255336 -267.755878)
		(end 348.31274 -267.698474)
		(width 0.088646)
		(layer "In11.Cu")
		(net "M_D_CPU0_SA_DQS_DN<8>")
	)
	(segment
		(start 295.365678 -283.30906)
		(end 295.084246 -283.590492)
		(width 0.18288)
		(layer "In11.Cu")
		(net "M_D_CPU0_SA_DQS_DN<8>")
	)
	(segment
		(start 278.601932 -283.333698)
		(end 278.001476 -282.733242)
		(width 0.18288)
		(layer "In11.Cu")
		(net "M_D_CPU0_SA_DQS_DN<8>")
	)
	(segment
		(start 330.986384 -269.02029)
		(end 330.92644 -269.080234)
		(width 0.088646)
		(layer "In11.Cu")
		(net "M_D_CPU0_SA_DQS_DN<8>")
	)
	(segment
		(start 312.742072 -280.115772)
		(end 312.617612 -279.991312)
		(width 0.18288)
		(layer "In11.Cu")
		(net "M_D_CPU0_SA_DQS_DN<8>")
	)
	(segment
		(start 311.403492 -279.991312)
		(end 310.670956 -280.723848)
		(width 0.18288)
		(layer "In11.Cu")
		(net "M_D_CPU0_SA_DQS_DN<8>")
	)
	(segment
		(start 344.936318 -267.43152)
		(end 344.925904 -267.437616)
		(width 0.088646)
		(layer "In11.Cu")
		(net "M_D_CPU0_SA_DQS_DN<8>")
	)
	(segment
		(start 340.237064 -267.43152)
		(end 340.222332 -267.440156)
		(width 0.088646)
		(layer "In11.Cu")
		(net "M_D_CPU0_SA_DQS_DN<8>")
	)
	(segment
		(start 346.815664 -267.43152)
		(end 346.800932 -267.440156)
		(width 0.088646)
		(layer "In11.Cu")
		(net "M_D_CPU0_SA_DQS_DN<8>")
	)
	(segment
		(start 293.694866 -283.313632)
		(end 293.11346 -282.732226)
		(width 0.18288)
		(layer "In11.Cu")
		(net "M_D_CPU0_SA_DQS_DN<8>")
	)
	(segment
		(start 293.11346 -282.732226)
		(end 292.311328 -282.732226)
		(width 0.18288)
		(layer "In11.Cu")
		(net "M_D_CPU0_SA_DQS_DN<8>")
	)
	(segment
		(start 291.90823 -283.135324)
		(end 291.201094 -283.428186)
		(width 0.18288)
		(layer "In11.Cu")
		(net "M_D_CPU0_SA_DQS_DN<8>")
	)
	(segment
		(start 299.202602 -282.740608)
		(end 298.801282 -282.740608)
		(width 0.18288)
		(layer "In11.Cu")
		(net "M_D_CPU0_SA_DQS_DN<8>")
	)
	(segment
		(start 331.493114 -268.682216)
		(end 331.493114 -268.805152)
		(width 0.088646)
		(layer "In11.Cu")
		(net "M_D_CPU0_SA_DQS_DN<8>")
	)
	(segment
		(start 282.87091 -282.82392)
		(end 281.673046 -283.32049)
		(width 0.18288)
		(layer "In11.Cu")
		(net "M_D_CPU0_SA_DQS_DN<8>")
	)
	(segment
		(start 343.056464 -267.43152)
		(end 343.041732 -267.440156)
		(width 0.088646)
		(layer "In11.Cu")
		(net "M_D_CPU0_SA_DQS_DN<8>")
	)
	(segment
		(start 325.684896 -269.080234)
		(end 314.773818 -279.991312)
		(width 0.18288)
		(layer "In11.Cu")
		(net "M_D_CPU0_SA_DQS_DN<8>")
	)
	(segment
		(start 303.172622 -282.483814)
		(end 299.459396 -282.483814)
		(width 0.18288)
		(layer "In11.Cu")
		(net "M_D_CPU0_SA_DQS_DN<8>")
	)
	(segment
		(start 305.2572 -281.85364)
		(end 305.13274 -281.72918)
		(width 0.18288)
		(layer "In11.Cu")
		(net "M_D_CPU0_SA_DQS_DN<8>")
	)
	(segment
		(start 276.173184 -283.229304)
		(end 274.379944 -283.229304)
		(width 0.18288)
		(layer "In11.Cu")
		(net "M_D_CPU0_SA_DQS_DN<8>")
	)
	(segment
		(start 294.429434 -283.313632)
		(end 293.694866 -283.313632)
		(width 0.18288)
		(layer "In11.Cu")
		(net "M_D_CPU0_SA_DQS_DN<8>")
	)
	(segment
		(start 305.80584 -281.85364)
		(end 305.2572 -281.85364)
		(width 0.18288)
		(layer "In11.Cu")
		(net "M_D_CPU0_SA_DQS_DN<8>")
	)
	(segment
		(start 332.190344 -267.507212)
		(end 332.05674 -267.562838)
		(width 0.088646)
		(layer "In11.Cu")
		(net "M_D_CPU0_SA_DQS_DN<8>")
	)
	(segment
		(start 280.011632 -283.592778)
		(end 279.626568 -283.592778)
		(width 0.18288)
		(layer "In11.Cu")
		(net "M_D_CPU0_SA_DQS_DN<8>")
	)
	(segment
		(start 269.506446 -283.732732)
		(end 269.113254 -283.732732)
		(width 0.18288)
		(layer "In11.Cu")
		(net "M_D_CPU0_SA_DQS_DN<8>")
	)
	(segment
		(start 309.173118 -281.027378)
		(end 307.523642 -281.027378)
		(width 0.18288)
		(layer "In11.Cu")
		(net "M_D_CPU0_SA_DQS_DN<8>")
	)
	(segment
		(start 338.742528 -267.437616)
		(end 338.732114 -267.43152)
		(width 0.088646)
		(layer "In11.Cu")
		(net "M_D_CPU0_SA_DQS_DN<8>")
	)
	(segment
		(start 347.755464 -267.43152)
		(end 347.740732 -267.440156)
		(width 0.088646)
		(layer "In11.Cu")
		(net "M_D_CPU0_SA_DQS_DN<8>")
	)
	(segment
		(start 283.726382 -282.74264)
		(end 283.455872 -282.47213)
		(width 0.18288)
		(layer "In11.Cu")
		(net "M_D_CPU0_SA_DQS_DN<8>")
	)
	(segment
		(start 280.28392 -283.32049)
		(end 280.011632 -283.592778)
		(width 0.18288)
		(layer "In11.Cu")
		(net "M_D_CPU0_SA_DQS_DN<8>")
	)
	(segment
		(start 347.942662 -267.755878)
		(end 348.255336 -267.755878)
		(width 0.088646)
		(layer "In11.Cu")
		(net "M_D_CPU0_SA_DQS_DN<8>")
	)
	(segment
		(start 305.9303 -281.72918)
		(end 305.80584 -281.85364)
		(width 0.18288)
		(layer "In11.Cu")
		(net "M_D_CPU0_SA_DQS_DN<8>")
	)
	(segment
		(start 343.996264 -267.43152)
		(end 343.981532 -267.440156)
		(width 0.088646)
		(layer "In11.Cu")
		(net "M_D_CPU0_SA_DQS_DN<8>")
	)
	(segment
		(start 336.478372 -267.431266)
		(end 336.477864 -267.43152)
		(width 0.088646)
		(layer "In11.Cu")
		(net "M_D_CPU0_SA_DQS_DN<8>")
	)
	(segment
		(start 298.801282 -282.740608)
		(end 298.523406 -282.462732)
		(width 0.18288)
		(layer "In11.Cu")
		(net "M_D_CPU0_SA_DQS_DN<8>")
	)
	(segment
		(start 305.13274 -281.72918)
		(end 303.927256 -281.72918)
		(width 0.18288)
		(layer "In11.Cu")
		(net "M_D_CPU0_SA_DQS_DN<8>")
	)
	(segment
		(start 313.290712 -280.115772)
		(end 312.742072 -280.115772)
		(width 0.18288)
		(layer "In11.Cu")
		(net "M_D_CPU0_SA_DQS_DN<8>")
	)
	(segment
		(start 277.371302 -282.733242)
		(end 276.173184 -283.229304)
		(width 0.18288)
		(layer "In11.Cu")
		(net "M_D_CPU0_SA_DQS_DN<8>")
	)
	(segment
		(start 284.386528 -282.454858)
		(end 284.098746 -282.74264)
		(width 0.18288)
		(layer "In11.Cu")
		(net "M_D_CPU0_SA_DQS_DN<8>")
	)
	(segment
		(start 269.745714 -283.972)
		(end 269.506446 -283.732732)
		(width 0.18288)
		(layer "In11.Cu")
		(net "M_D_CPU0_SA_DQS_DN<8>")
	)
	(segment
		(start 331.277976 -269.02029)
		(end 330.986384 -269.02029)
		(width 0.088646)
		(layer "In11.Cu")
		(net "M_D_CPU0_SA_DQS_DN<8>")
	)
	(segment
		(start 287.36036 -282.454858)
		(end 284.386528 -282.454858)
		(width 0.18288)
		(layer "In11.Cu")
		(net "M_D_CPU0_SA_DQS_DN<8>")
	)
	(segment
		(start 279.626568 -283.592778)
		(end 279.367488 -283.333698)
		(width 0.18288)
		(layer "In11.Cu")
		(net "M_D_CPU0_SA_DQS_DN<8>")
	)
	(segment
		(start 299.459396 -282.483814)
		(end 299.202602 -282.740608)
		(width 0.18288)
		(layer "In11.Cu")
		(net "M_D_CPU0_SA_DQS_DN<8>")
	)
	(segment
		(start 281.673046 -283.32049)
		(end 280.28392 -283.32049)
		(width 0.18288)
		(layer "In11.Cu")
		(net "M_D_CPU0_SA_DQS_DN<8>")
	)
	(segment
		(start 309.476648 -280.723848)
		(end 309.173118 -281.027378)
		(width 0.18288)
		(layer "In11.Cu")
		(net "M_D_CPU0_SA_DQS_DN<8>")
	)
	(segment
		(start 298.523406 -282.462732)
		(end 297.787822 -282.462732)
		(width 0.18288)
		(layer "In11.Cu")
		(net "M_D_CPU0_SA_DQS_DN<8>")
	)
	(segment
		(start 289.70859 -283.428186)
		(end 287.36036 -282.454858)
		(width 0.18288)
		(layer "In11.Cu")
		(net "M_D_CPU0_SA_DQS_DN<8>")
	)
	(segment
		(start 283.2227 -282.47213)
		(end 282.87091 -282.82392)
		(width 0.18288)
		(layer "In11.Cu")
		(net "M_D_CPU0_SA_DQS_DN<8>")
	)
	(segment
		(start 278.001476 -282.733242)
		(end 277.371302 -282.733242)
		(width 0.18288)
		(layer "In11.Cu")
		(net "M_D_CPU0_SA_DQS_DN<8>")
	)
	(segment
		(start 312.617612 -279.991312)
		(end 311.403492 -279.991312)
		(width 0.18288)
		(layer "In11.Cu")
		(net "M_D_CPU0_SA_DQS_DN<8>")
	)
	(segment
		(start 331.788008 -268.387322)
		(end 331.493114 -268.682216)
		(width 0.088646)
		(layer "In11.Cu")
		(net "M_D_CPU0_SA_DQS_DN<8>")
	)
	(segment
		(start 332.43647 -267.507212)
		(end 332.190344 -267.507212)
		(width 0.088646)
		(layer "In11.Cu")
		(net "M_D_CPU0_SA_DQS_DN<8>")
	)
	(segment
		(start 294.706294 -283.590492)
		(end 294.429434 -283.313632)
		(width 0.18288)
		(layer "In11.Cu")
		(net "M_D_CPU0_SA_DQS_DN<8>")
	)
	(segment
		(start 291.201094 -283.428186)
		(end 289.70859 -283.428186)
		(width 0.18288)
		(layer "In11.Cu")
		(net "M_D_CPU0_SA_DQS_DN<8>")
	)
	(segment
		(start 332.05674 -267.562838)
		(end 331.788008 -267.831316)
		(width 0.088646)
		(layer "In11.Cu")
		(net "M_D_CPU0_SA_DQS_DN<8>")
	)
	(segment
		(start 297.787822 -282.462732)
		(end 296.941494 -283.30906)
		(width 0.18288)
		(layer "In11.Cu")
		(net "M_D_CPU0_SA_DQS_DN<8>")
	)
	(segment
		(start 272.586704 -283.972)
		(end 269.745714 -283.972)
		(width 0.18288)
		(layer "In11.Cu")
		(net "M_D_CPU0_SA_DQS_DN<8>")
	)
	(segment
		(start 296.941494 -283.30906)
		(end 295.365678 -283.30906)
		(width 0.18288)
		(layer "In11.Cu")
		(net "M_D_CPU0_SA_DQS_DN<8>")
	)
	(segment
		(start 306.82184 -281.72918)
		(end 305.9303 -281.72918)
		(width 0.18288)
		(layer "In11.Cu")
		(net "M_D_CPU0_SA_DQS_DN<8>")
	)
	(segment
		(start 279.367488 -283.333698)
		(end 278.601932 -283.333698)
		(width 0.18288)
		(layer "In11.Cu")
		(net "M_D_CPU0_SA_DQS_DN<8>")
	)
	(segment
		(start 330.92644 -269.080234)
		(end 325.684896 -269.080234)
		(width 0.18288)
		(layer "In11.Cu")
		(net "M_D_CPU0_SA_DQS_DN<8>")
	)
	(segment
		(start 345.321128 -267.437616)
		(end 345.310714 -267.43152)
		(width 0.088646)
		(layer "In11.Cu")
		(net "M_D_CPU0_SA_DQS_DN<8>")
	)
	(segment
		(start 337.802474 -267.437616)
		(end 337.79206 -267.43152)
		(width 0.088646)
		(layer "In11.Cu")
		(net "M_D_CPU0_SA_DQS_DN<8>")
	)
	(segment
		(start 303.927256 -281.72918)
		(end 303.172622 -282.483814)
		(width 0.18288)
		(layer "In11.Cu")
		(net "M_D_CPU0_SA_DQS_DN<8>")
	)
	(segment
		(start 283.455872 -282.47213)
		(end 283.2227 -282.47213)
		(width 0.18288)
		(layer "In11.Cu")
		(net "M_D_CPU0_SA_DQS_DN<8>")
	)
	(segment
		(start 313.415172 -279.991312)
		(end 313.290712 -280.115772)
		(width 0.18288)
		(layer "In11.Cu")
		(net "M_D_CPU0_SA_DQS_DN<8>")
	)
	(segment
		(start 284.098746 -282.74264)
		(end 283.726382 -282.74264)
		(width 0.18288)
		(layer "In11.Cu")
		(net "M_D_CPU0_SA_DQS_DN<8>")
	)
	(segment
		(start 331.493114 -268.805152)
		(end 331.277976 -269.02029)
		(width 0.088646)
		(layer "In11.Cu")
		(net "M_D_CPU0_SA_DQS_DN<8>")
	)
	(segment
		(start 342.116664 -267.43152)
		(end 342.101932 -267.440156)
		(width 0.088646)
		(layer "In11.Cu")
		(net "M_D_CPU0_SA_DQS_DN<8>")
	)
	(segment
		(start 307.523642 -281.027378)
		(end 306.82184 -281.72918)
		(width 0.18288)
		(layer "In11.Cu")
		(net "M_D_CPU0_SA_DQS_DN<8>")
	)
	(segment
		(start 295.084246 -283.590492)
		(end 294.706294 -283.590492)
		(width 0.18288)
		(layer "In11.Cu")
		(net "M_D_CPU0_SA_DQS_DN<8>")
	)
	(segment
		(start 274.379944 -283.229304)
		(end 272.586704 -283.972)
		(width 0.18288)
		(layer "In11.Cu")
		(net "M_D_CPU0_SA_DQS_DN<8>")
	)
	(segment
		(start 310.670956 -280.723848)
		(end 309.476648 -280.723848)
		(width 0.18288)
		(layer "In11.Cu")
		(net "M_D_CPU0_SA_DQS_DN<8>")
	)
	(segment
		(start 341.176864 -267.43152)
		(end 341.162132 -267.440156)
		(width 0.088646)
		(layer "In11.Cu")
		(net "M_D_CPU0_SA_DQS_DN<8>")
	)
	(arc
		(start 340.61146 -267.43152)
		(mid 340.424262 -267.381377)
		(end 340.237064 -267.43152)
		(width 0.088646)
		(layer "In11.Cu")
		(net "M_D_CPU0_SA_DQS_DN<8>")
	)
	(arc
		(start 334.97266 -267.43152)
		(mid 334.785462 -267.381377)
		(end 334.598264 -267.43152)
		(width 0.088646)
		(layer "In11.Cu")
		(net "M_D_CPU0_SA_DQS_DN<8>")
	)
	(arc
		(start 344.37066 -267.43152)
		(mid 344.183462 -267.381377)
		(end 343.996264 -267.43152)
		(width 0.088646)
		(layer "In11.Cu")
		(net "M_D_CPU0_SA_DQS_DN<8>")
	)
	(arc
		(start 343.981532 -267.440156)
		(mid 343.705091 -267.507322)
		(end 343.43086 -267.43152)
		(width 0.088646)
		(layer "In11.Cu")
		(net "M_D_CPU0_SA_DQS_DN<8>")
	)
	(arc
		(start 343.43086 -267.43152)
		(mid 343.243662 -267.381377)
		(end 343.056464 -267.43152)
		(width 0.088646)
		(layer "In11.Cu")
		(net "M_D_CPU0_SA_DQS_DN<8>")
	)
	(arc
		(start 332.718664 -267.43152)
		(mid 332.582544 -267.487933)
		(end 332.43647 -267.507212)
		(width 0.088646)
		(layer "In11.Cu")
		(net "M_D_CPU0_SA_DQS_DN<8>")
	)
	(arc
		(start 338.357718 -267.43152)
		(mid 338.080905 -267.507356)
		(end 337.802474 -267.437616)
		(width 0.088646)
		(layer "In11.Cu")
		(net "M_D_CPU0_SA_DQS_DN<8>")
	)
	(arc
		(start 336.477864 -267.43152)
		(mid 336.195162 -267.507262)
		(end 335.91246 -267.43152)
		(width 0.088646)
		(layer "In11.Cu")
		(net "M_D_CPU0_SA_DQS_DN<8>")
	)
	(arc
		(start 344.925904 -267.437616)
		(mid 344.647472 -267.50743)
		(end 344.37066 -267.43152)
		(width 0.088646)
		(layer "In11.Cu")
		(net "M_D_CPU0_SA_DQS_DN<8>")
	)
	(arc
		(start 347.740732 -267.440156)
		(mid 347.464291 -267.507322)
		(end 347.19006 -267.43152)
		(width 0.088646)
		(layer "In11.Cu")
		(net "M_D_CPU0_SA_DQS_DN<8>")
	)
	(arc
		(start 334.03286 -267.43152)
		(mid 333.845662 -267.381377)
		(end 333.658464 -267.43152)
		(width 0.088646)
		(layer "In11.Cu")
		(net "M_D_CPU0_SA_DQS_DN<8>")
	)
	(arc
		(start 348.31274 -267.698474)
		(mid 348.104457 -267.418128)
		(end 347.755464 -267.43152)
		(width 0.088646)
		(layer "In11.Cu")
		(net "M_D_CPU0_SA_DQS_DN<8>")
	)
	(arc
		(start 342.49106 -267.43152)
		(mid 342.303862 -267.381377)
		(end 342.116664 -267.43152)
		(width 0.088646)
		(layer "In11.Cu")
		(net "M_D_CPU0_SA_DQS_DN<8>")
	)
	(arc
		(start 333.09306 -267.43152)
		(mid 332.905862 -267.381377)
		(end 332.718664 -267.43152)
		(width 0.088646)
		(layer "In11.Cu")
		(net "M_D_CPU0_SA_DQS_DN<8>")
	)
	(arc
		(start 342.101932 -267.440156)
		(mid 341.825491 -267.507322)
		(end 341.55126 -267.43152)
		(width 0.088646)
		(layer "In11.Cu")
		(net "M_D_CPU0_SA_DQS_DN<8>")
	)
	(arc
		(start 345.310714 -267.43152)
		(mid 345.123516 -267.381377)
		(end 344.936318 -267.43152)
		(width 0.088646)
		(layer "In11.Cu")
		(net "M_D_CPU0_SA_DQS_DN<8>")
	)
	(arc
		(start 341.55126 -267.43152)
		(mid 341.364062 -267.381377)
		(end 341.176864 -267.43152)
		(width 0.088646)
		(layer "In11.Cu")
		(net "M_D_CPU0_SA_DQS_DN<8>")
	)
	(arc
		(start 336.85226 -267.43152)
		(mid 336.665345 -267.381377)
		(end 336.478372 -267.431266)
		(width 0.088646)
		(layer "In11.Cu")
		(net "M_D_CPU0_SA_DQS_DN<8>")
	)
	(arc
		(start 340.222332 -267.440156)
		(mid 339.945891 -267.507322)
		(end 339.67166 -267.43152)
		(width 0.088646)
		(layer "In11.Cu")
		(net "M_D_CPU0_SA_DQS_DN<8>")
	)
	(arc
		(start 339.297264 -267.43152)
		(mid 339.020705 -267.507229)
		(end 338.742528 -267.437616)
		(width 0.088646)
		(layer "In11.Cu")
		(net "M_D_CPU0_SA_DQS_DN<8>")
	)
	(arc
		(start 337.79206 -267.43152)
		(mid 337.604862 -267.381377)
		(end 337.417664 -267.43152)
		(width 0.088646)
		(layer "In11.Cu")
		(net "M_D_CPU0_SA_DQS_DN<8>")
	)
	(arc
		(start 334.598264 -267.43152)
		(mid 334.315562 -267.507262)
		(end 334.03286 -267.43152)
		(width 0.088646)
		(layer "In11.Cu")
		(net "M_D_CPU0_SA_DQS_DN<8>")
	)
	(arc
		(start 339.67166 -267.43152)
		(mid 339.484462 -267.381377)
		(end 339.297264 -267.43152)
		(width 0.088646)
		(layer "In11.Cu")
		(net "M_D_CPU0_SA_DQS_DN<8>")
	)
	(arc
		(start 346.800932 -267.440156)
		(mid 346.524491 -267.507322)
		(end 346.25026 -267.43152)
		(width 0.088646)
		(layer "In11.Cu")
		(net "M_D_CPU0_SA_DQS_DN<8>")
	)
	(arc
		(start 335.91246 -267.43152)
		(mid 335.725262 -267.381377)
		(end 335.538064 -267.43152)
		(width 0.088646)
		(layer "In11.Cu")
		(net "M_D_CPU0_SA_DQS_DN<8>")
	)
	(arc
		(start 343.041732 -267.440156)
		(mid 342.765291 -267.507322)
		(end 342.49106 -267.43152)
		(width 0.088646)
		(layer "In11.Cu")
		(net "M_D_CPU0_SA_DQS_DN<8>")
	)
	(arc
		(start 346.25026 -267.43152)
		(mid 346.063062 -267.381377)
		(end 345.875864 -267.43152)
		(width 0.088646)
		(layer "In11.Cu")
		(net "M_D_CPU0_SA_DQS_DN<8>")
	)
	(arc
		(start 333.658464 -267.43152)
		(mid 333.375762 -267.507262)
		(end 333.09306 -267.43152)
		(width 0.088646)
		(layer "In11.Cu")
		(net "M_D_CPU0_SA_DQS_DN<8>")
	)
	(arc
		(start 347.19006 -267.43152)
		(mid 347.002862 -267.381377)
		(end 346.815664 -267.43152)
		(width 0.088646)
		(layer "In11.Cu")
		(net "M_D_CPU0_SA_DQS_DN<8>")
	)
	(arc
		(start 345.875864 -267.43152)
		(mid 345.599305 -267.507229)
		(end 345.321128 -267.437616)
		(width 0.088646)
		(layer "In11.Cu")
		(net "M_D_CPU0_SA_DQS_DN<8>")
	)
	(arc
		(start 341.162132 -267.440156)
		(mid 340.885691 -267.507322)
		(end 340.61146 -267.43152)
		(width 0.088646)
		(layer "In11.Cu")
		(net "M_D_CPU0_SA_DQS_DN<8>")
	)
	(arc
		(start 337.417664 -267.43152)
		(mid 337.134962 -267.507262)
		(end 336.85226 -267.43152)
		(width 0.088646)
		(layer "In11.Cu")
		(net "M_D_CPU0_SA_DQS_DN<8>")
	)
	(arc
		(start 335.538064 -267.43152)
		(mid 335.255362 -267.507262)
		(end 334.97266 -267.43152)
		(width 0.088646)
		(layer "In11.Cu")
		(net "M_D_CPU0_SA_DQS_DN<8>")
	)
	(arc
		(start 338.732114 -267.43152)
		(mid 338.544916 -267.381377)
		(end 338.357718 -267.43152)
		(width 0.088646)
		(layer "In11.Cu")
		(net "M_D_CPU0_SA_DQS_DN<8>")
	)
	(segment
		(start 267.724382 -293.366698)
		(end 267.233908 -293.366698)
		(width 0.20066)
		(layer "F.Cu")
		(net "M_D_CPU0_SA_DQS_DN<7>")
	)
	(segment
		(start 262.511286 -292.941756)
		(end 262.501634 -292.951408)
		(width 0.101854)
		(layer "F.Cu")
		(net "M_D_CPU0_SA_DQS_DN<7>")
	)
	(segment
		(start 262.316976 -292.951408)
		(end 262.048752 -292.683184)
		(width 0.20066)
		(layer "F.Cu")
		(net "M_D_CPU0_SA_DQS_DN<7>")
	)
	(segment
		(start 265.228578 -292.680644)
		(end 264.967466 -292.941756)
		(width 0.20066)
		(layer "F.Cu")
		(net "M_D_CPU0_SA_DQS_DN<7>")
	)
	(segment
		(start 266.972796 -293.105586)
		(end 266.269216 -293.105586)
		(width 0.20066)
		(layer "F.Cu")
		(net "M_D_CPU0_SA_DQS_DN<7>")
	)
	(segment
		(start 264.967466 -292.941756)
		(end 264.825226 -292.941756)
		(width 0.20066)
		(layer "F.Cu")
		(net "M_D_CPU0_SA_DQS_DN<7>")
	)
	(segment
		(start 266.269216 -293.105586)
		(end 265.6332 -292.680644)
		(width 0.20066)
		(layer "F.Cu")
		(net "M_D_CPU0_SA_DQS_DN<7>")
	)
	(segment
		(start 268.829282 -293.366698)
		(end 267.724382 -293.366698)
		(width 0.20066)
		(layer "F.Cu")
		(net "M_D_CPU0_SA_DQS_DN<7>")
	)
	(segment
		(start 262.50011 -292.951408)
		(end 262.316976 -292.951408)
		(width 0.20066)
		(layer "F.Cu")
		(net "M_D_CPU0_SA_DQS_DN<7>")
	)
	(segment
		(start 260.65226 -293.366698)
		(end 260.180582 -293.366698)
		(width 0.20066)
		(layer "F.Cu")
		(net "M_D_CPU0_SA_DQS_DN<7>")
	)
	(segment
		(start 265.6332 -292.680644)
		(end 265.228578 -292.680644)
		(width 0.20066)
		(layer "F.Cu")
		(net "M_D_CPU0_SA_DQS_DN<7>")
	)
	(segment
		(start 267.233908 -293.366698)
		(end 266.972796 -293.105586)
		(width 0.20066)
		(layer "F.Cu")
		(net "M_D_CPU0_SA_DQS_DN<7>")
	)
	(segment
		(start 264.825226 -292.941756)
		(end 262.74776 -292.941756)
		(width 0.1016)
		(layer "F.Cu")
		(net "M_D_CPU0_SA_DQS_DN<7>")
	)
	(segment
		(start 262.048752 -292.683184)
		(end 261.808976 -292.683184)
		(width 0.20066)
		(layer "F.Cu")
		(net "M_D_CPU0_SA_DQS_DN<7>")
	)
	(segment
		(start 260.913372 -293.105586)
		(end 260.65226 -293.366698)
		(width 0.20066)
		(layer "F.Cu")
		(net "M_D_CPU0_SA_DQS_DN<7>")
	)
	(segment
		(start 261.808976 -292.683184)
		(end 261.386574 -293.105586)
		(width 0.20066)
		(layer "F.Cu")
		(net "M_D_CPU0_SA_DQS_DN<7>")
	)
	(segment
		(start 261.386574 -293.105586)
		(end 260.913372 -293.105586)
		(width 0.20066)
		(layer "F.Cu")
		(net "M_D_CPU0_SA_DQS_DN<7>")
	)
	(segment
		(start 262.501634 -292.951408)
		(end 262.50011 -292.951408)
		(width 0.101854)
		(layer "F.Cu")
		(net "M_D_CPU0_SA_DQS_DN<7>")
	)
	(segment
		(start 262.74776 -292.941756)
		(end 262.511286 -292.941756)
		(width 0.101854)
		(layer "F.Cu")
		(net "M_D_CPU0_SA_DQS_DN<7>")
	)
	(arc
		(start 347.942916 -272.103342)
		(mid 347.942852 -272.371312)
		(end 347.942662 -272.639282)
		(width 0.20066)
		(layer "F.Cu")
		(net "M_D_CPU0_SA_DQS_DN<7>")
	)
	(segment
		(start 308.514496 -290.50742)
		(end 308.390036 -290.38296)
		(width 0.18288)
		(layer "In11.Cu")
		(net "M_D_CPU0_SA_DQS_DN<7>")
	)
	(segment
		(start 293.089838 -294.616886)
		(end 292.36035 -294.616886)
		(width 0.18288)
		(layer "In11.Cu")
		(net "M_D_CPU0_SA_DQS_DN<7>")
	)
	(segment
		(start 291.924486 -295.05275)
		(end 291.280342 -295.05275)
		(width 0.18288)
		(layer "In11.Cu")
		(net "M_D_CPU0_SA_DQS_DN<7>")
	)
	(segment
		(start 313.554872 -289.294316)
		(end 313.430412 -289.418776)
		(width 0.18288)
		(layer "In11.Cu")
		(net "M_D_CPU0_SA_DQS_DN<7>")
	)
	(segment
		(start 309.187596 -290.38296)
		(end 309.063136 -290.50742)
		(width 0.18288)
		(layer "In11.Cu")
		(net "M_D_CPU0_SA_DQS_DN<7>")
	)
	(segment
		(start 276.251416 -295.391586)
		(end 274.807172 -293.947342)
		(width 0.18288)
		(layer "In11.Cu")
		(net "M_D_CPU0_SA_DQS_DN<7>")
	)
	(segment
		(start 280.078942 -295.4909)
		(end 279.590246 -295.4909)
		(width 0.18288)
		(layer "In11.Cu")
		(net "M_D_CPU0_SA_DQS_DN<7>")
	)
	(segment
		(start 304.724054 -292.472872)
		(end 302.803814 -293.268146)
		(width 0.18288)
		(layer "In11.Cu")
		(net "M_D_CPU0_SA_DQS_DN<7>")
	)
	(segment
		(start 283.429456 -294.385492)
		(end 283.408628 -294.364664)
		(width 0.18288)
		(layer "In11.Cu")
		(net "M_D_CPU0_SA_DQS_DN<7>")
	)
	(segment
		(start 302.803814 -293.268146)
		(end 301.562516 -293.268146)
		(width 0.18288)
		(layer "In11.Cu")
		(net "M_D_CPU0_SA_DQS_DN<7>")
	)
	(segment
		(start 279.317958 -295.218612)
		(end 278.808942 -295.218612)
		(width 0.18288)
		(layer "In11.Cu")
		(net "M_D_CPU0_SA_DQS_DN<7>")
	)
	(segment
		(start 346.815664 -272.314924)
		(end 346.800932 -272.32356)
		(width 0.088646)
		(layer "In11.Cu")
		(net "M_D_CPU0_SA_DQS_DN<7>")
	)
	(segment
		(start 285.632906 -294.371268)
		(end 284.373828 -294.371268)
		(width 0.18288)
		(layer "In11.Cu")
		(net "M_D_CPU0_SA_DQS_DN<7>")
	)
	(segment
		(start 292.36035 -294.616886)
		(end 291.924486 -295.05275)
		(width 0.18288)
		(layer "In11.Cu")
		(net "M_D_CPU0_SA_DQS_DN<7>")
	)
	(segment
		(start 299.199046 -294.640762)
		(end 298.777914 -294.640762)
		(width 0.18288)
		(layer "In11.Cu")
		(net "M_D_CPU0_SA_DQS_DN<7>")
	)
	(segment
		(start 276.617938 -295.391586)
		(end 276.251416 -295.391586)
		(width 0.18288)
		(layer "In11.Cu")
		(net "M_D_CPU0_SA_DQS_DN<7>")
	)
	(segment
		(start 337.417664 -272.314924)
		(end 337.40725 -272.32102)
		(width 0.088646)
		(layer "In11.Cu")
		(net "M_D_CPU0_SA_DQS_DN<7>")
	)
	(segment
		(start 270.034766 -293.318692)
		(end 269.486126 -293.091616)
		(width 0.18288)
		(layer "In11.Cu")
		(net "M_D_CPU0_SA_DQS_DN<7>")
	)
	(segment
		(start 306.654708 -291.218366)
		(end 305.978306 -291.218366)
		(width 0.18288)
		(layer "In11.Cu")
		(net "M_D_CPU0_SA_DQS_DN<7>")
	)
	(segment
		(start 308.390036 -290.38296)
		(end 307.490114 -290.38296)
		(width 0.18288)
		(layer "In11.Cu")
		(net "M_D_CPU0_SA_DQS_DN<7>")
	)
	(segment
		(start 283.690314 -294.640762)
		(end 283.435044 -294.385492)
		(width 0.18288)
		(layer "In11.Cu")
		(net "M_D_CPU0_SA_DQS_DN<7>")
	)
	(segment
		(start 333.103728 -272.32102)
		(end 333.093314 -272.314924)
		(width 0.088646)
		(layer "In11.Cu")
		(net "M_D_CPU0_SA_DQS_DN<7>")
	)
	(segment
		(start 283.435044 -294.385492)
		(end 283.429456 -294.385492)
		(width 0.18288)
		(layer "In11.Cu")
		(net "M_D_CPU0_SA_DQS_DN<7>")
	)
	(segment
		(start 343.996264 -272.314924)
		(end 343.981532 -272.32356)
		(width 0.088646)
		(layer "In11.Cu")
		(net "M_D_CPU0_SA_DQS_DN<7>")
	)
	(segment
		(start 331.088238 -275.03501)
		(end 331.028294 -275.094954)
		(width 0.088646)
		(layer "In11.Cu")
		(net "M_D_CPU0_SA_DQS_DN<7>")
	)
	(segment
		(start 309.063136 -290.50742)
		(end 308.514496 -290.50742)
		(width 0.18288)
		(layer "In11.Cu")
		(net "M_D_CPU0_SA_DQS_DN<7>")
	)
	(segment
		(start 310.668416 -290.38296)
		(end 309.187596 -290.38296)
		(width 0.18288)
		(layer "In11.Cu")
		(net "M_D_CPU0_SA_DQS_DN<7>")
	)
	(segment
		(start 331.300328 -275.03501)
		(end 331.088238 -275.03501)
		(width 0.088646)
		(layer "In11.Cu")
		(net "M_D_CPU0_SA_DQS_DN<7>")
	)
	(segment
		(start 294.71239 -295.4909)
		(end 294.443658 -295.222168)
		(width 0.18288)
		(layer "In11.Cu")
		(net "M_D_CPU0_SA_DQS_DN<7>")
	)
	(segment
		(start 284.104334 -294.640762)
		(end 283.690314 -294.640762)
		(width 0.18288)
		(layer "In11.Cu")
		(net "M_D_CPU0_SA_DQS_DN<7>")
	)
	(segment
		(start 269.486126 -293.091616)
		(end 269.104364 -293.091616)
		(width 0.18288)
		(layer "In11.Cu")
		(net "M_D_CPU0_SA_DQS_DN<7>")
	)
	(segment
		(start 286.818578 -294.324532)
		(end 286.694118 -294.200072)
		(width 0.18288)
		(layer "In11.Cu")
		(net "M_D_CPU0_SA_DQS_DN<7>")
	)
	(segment
		(start 298.777914 -294.640762)
		(end 298.568364 -294.431212)
		(width 0.18288)
		(layer "In11.Cu")
		(net "M_D_CPU0_SA_DQS_DN<7>")
	)
	(segment
		(start 284.373828 -294.371268)
		(end 284.104334 -294.640762)
		(width 0.18288)
		(layer "In11.Cu")
		(net "M_D_CPU0_SA_DQS_DN<7>")
	)
	(segment
		(start 312.757312 -289.294316)
		(end 311.75706 -289.294316)
		(width 0.18288)
		(layer "In11.Cu")
		(net "M_D_CPU0_SA_DQS_DN<7>")
	)
	(segment
		(start 301.562516 -293.268146)
		(end 300.445678 -294.38473)
		(width 0.18288)
		(layer "In11.Cu")
		(net "M_D_CPU0_SA_DQS_DN<7>")
	)
	(segment
		(start 331.028294 -275.094954)
		(end 328.425048 -275.094954)
		(width 0.18288)
		(layer "In11.Cu")
		(net "M_D_CPU0_SA_DQS_DN<7>")
	)
	(segment
		(start 338.742528 -272.32102)
		(end 338.732114 -272.314924)
		(width 0.088646)
		(layer "In11.Cu")
		(net "M_D_CPU0_SA_DQS_DN<7>")
	)
	(segment
		(start 274.807172 -293.947342)
		(end 273.289014 -293.318692)
		(width 0.18288)
		(layer "In11.Cu")
		(net "M_D_CPU0_SA_DQS_DN<7>")
	)
	(segment
		(start 300.445678 -294.38473)
		(end 299.455078 -294.38473)
		(width 0.18288)
		(layer "In11.Cu")
		(net "M_D_CPU0_SA_DQS_DN<7>")
	)
	(segment
		(start 278.181562 -295.845992)
		(end 277.072344 -295.845992)
		(width 0.18288)
		(layer "In11.Cu")
		(net "M_D_CPU0_SA_DQS_DN<7>")
	)
	(segment
		(start 286.694118 -294.200072)
		(end 286.046164 -294.200072)
		(width 0.18288)
		(layer "In11.Cu")
		(net "M_D_CPU0_SA_DQS_DN<7>")
	)
	(segment
		(start 280.34996 -295.219882)
		(end 280.078942 -295.4909)
		(width 0.18288)
		(layer "In11.Cu")
		(net "M_D_CPU0_SA_DQS_DN<7>")
	)
	(segment
		(start 291.280342 -295.05275)
		(end 290.622228 -294.816276)
		(width 0.18288)
		(layer "In11.Cu")
		(net "M_D_CPU0_SA_DQS_DN<7>")
	)
	(segment
		(start 313.430412 -289.418776)
		(end 312.881772 -289.418776)
		(width 0.18288)
		(layer "In11.Cu")
		(net "M_D_CPU0_SA_DQS_DN<7>")
	)
	(segment
		(start 298.159932 -294.431212)
		(end 296.809668 -295.223184)
		(width 0.18288)
		(layer "In11.Cu")
		(net "M_D_CPU0_SA_DQS_DN<7>")
	)
	(segment
		(start 347.755464 -272.314924)
		(end 347.740732 -272.32356)
		(width 0.088646)
		(layer "In11.Cu")
		(net "M_D_CPU0_SA_DQS_DN<7>")
	)
	(segment
		(start 331.533246 -274.46351)
		(end 331.533246 -274.802092)
		(width 0.088646)
		(layer "In11.Cu")
		(net "M_D_CPU0_SA_DQS_DN<7>")
	)
	(segment
		(start 328.425048 -275.094954)
		(end 314.225686 -289.294316)
		(width 0.18288)
		(layer "In11.Cu")
		(net "M_D_CPU0_SA_DQS_DN<7>")
	)
	(segment
		(start 347.942662 -272.639282)
		(end 348.255336 -272.639282)
		(width 0.088646)
		(layer "In11.Cu")
		(net "M_D_CPU0_SA_DQS_DN<7>")
	)
	(segment
		(start 277.072344 -295.845992)
		(end 276.617938 -295.391586)
		(width 0.18288)
		(layer "In11.Cu")
		(net "M_D_CPU0_SA_DQS_DN<7>")
	)
	(segment
		(start 294.443658 -295.222168)
		(end 293.69512 -295.222168)
		(width 0.18288)
		(layer "In11.Cu")
		(net "M_D_CPU0_SA_DQS_DN<7>")
	)
	(segment
		(start 295.360598 -295.223184)
		(end 295.092882 -295.4909)
		(width 0.18288)
		(layer "In11.Cu")
		(net "M_D_CPU0_SA_DQS_DN<7>")
	)
	(segment
		(start 299.455078 -294.38473)
		(end 299.199046 -294.640762)
		(width 0.18288)
		(layer "In11.Cu")
		(net "M_D_CPU0_SA_DQS_DN<7>")
	)
	(segment
		(start 311.75706 -289.294316)
		(end 310.668416 -290.38296)
		(width 0.18288)
		(layer "In11.Cu")
		(net "M_D_CPU0_SA_DQS_DN<7>")
	)
	(segment
		(start 334.043274 -272.32102)
		(end 334.03286 -272.314924)
		(width 0.088646)
		(layer "In11.Cu")
		(net "M_D_CPU0_SA_DQS_DN<7>")
	)
	(segment
		(start 307.490114 -290.38296)
		(end 306.654708 -291.218366)
		(width 0.18288)
		(layer "In11.Cu")
		(net "M_D_CPU0_SA_DQS_DN<7>")
	)
	(segment
		(start 332.75778 -272.264124)
		(end 332.415134 -272.60677)
		(width 0.088646)
		(layer "In11.Cu")
		(net "M_D_CPU0_SA_DQS_DN<7>")
	)
	(segment
		(start 295.092882 -295.4909)
		(end 294.71239 -295.4909)
		(width 0.18288)
		(layer "In11.Cu")
		(net "M_D_CPU0_SA_DQS_DN<7>")
	)
	(segment
		(start 287.367218 -294.324532)
		(end 286.818578 -294.324532)
		(width 0.18288)
		(layer "In11.Cu")
		(net "M_D_CPU0_SA_DQS_DN<7>")
	)
	(segment
		(start 278.808942 -295.218612)
		(end 278.181562 -295.845992)
		(width 0.18288)
		(layer "In11.Cu")
		(net "M_D_CPU0_SA_DQS_DN<7>")
	)
	(segment
		(start 296.809668 -295.223184)
		(end 295.360598 -295.223184)
		(width 0.18288)
		(layer "In11.Cu")
		(net "M_D_CPU0_SA_DQS_DN<7>")
	)
	(segment
		(start 293.69512 -295.222168)
		(end 293.089838 -294.616886)
		(width 0.18288)
		(layer "In11.Cu")
		(net "M_D_CPU0_SA_DQS_DN<7>")
	)
	(segment
		(start 305.978306 -291.218366)
		(end 304.724054 -292.472872)
		(width 0.18288)
		(layer "In11.Cu")
		(net "M_D_CPU0_SA_DQS_DN<7>")
	)
	(segment
		(start 298.568364 -294.431212)
		(end 298.159932 -294.431212)
		(width 0.18288)
		(layer "In11.Cu")
		(net "M_D_CPU0_SA_DQS_DN<7>")
	)
	(segment
		(start 341.176864 -272.314924)
		(end 341.162132 -272.32356)
		(width 0.088646)
		(layer "In11.Cu")
		(net "M_D_CPU0_SA_DQS_DN<7>")
	)
	(segment
		(start 286.046164 -294.200072)
		(end 285.632906 -294.371268)
		(width 0.18288)
		(layer "In11.Cu")
		(net "M_D_CPU0_SA_DQS_DN<7>")
	)
	(segment
		(start 288.255964 -294.200072)
		(end 287.491678 -294.200072)
		(width 0.18288)
		(layer "In11.Cu")
		(net "M_D_CPU0_SA_DQS_DN<7>")
	)
	(segment
		(start 283.408628 -294.364664)
		(end 282.935172 -294.364664)
		(width 0.18288)
		(layer "In11.Cu")
		(net "M_D_CPU0_SA_DQS_DN<7>")
	)
	(segment
		(start 288.694368 -293.761668)
		(end 288.255964 -294.200072)
		(width 0.18288)
		(layer "In11.Cu")
		(net "M_D_CPU0_SA_DQS_DN<7>")
	)
	(segment
		(start 273.289014 -293.318692)
		(end 270.034766 -293.318692)
		(width 0.18288)
		(layer "In11.Cu")
		(net "M_D_CPU0_SA_DQS_DN<7>")
	)
	(segment
		(start 337.802474 -272.32102)
		(end 337.79206 -272.314924)
		(width 0.088646)
		(layer "In11.Cu")
		(net "M_D_CPU0_SA_DQS_DN<7>")
	)
	(segment
		(start 289.567874 -293.761668)
		(end 288.694368 -293.761668)
		(width 0.18288)
		(layer "In11.Cu")
		(net "M_D_CPU0_SA_DQS_DN<7>")
	)
	(segment
		(start 312.881772 -289.418776)
		(end 312.757312 -289.294316)
		(width 0.18288)
		(layer "In11.Cu")
		(net "M_D_CPU0_SA_DQS_DN<7>")
	)
	(segment
		(start 282.935172 -294.364664)
		(end 282.079954 -295.219882)
		(width 0.18288)
		(layer "In11.Cu")
		(net "M_D_CPU0_SA_DQS_DN<7>")
	)
	(segment
		(start 332.905862 -272.264124)
		(end 332.75778 -272.264124)
		(width 0.088646)
		(layer "In11.Cu")
		(net "M_D_CPU0_SA_DQS_DN<7>")
	)
	(segment
		(start 332.415134 -272.60677)
		(end 332.415134 -273.581622)
		(width 0.088646)
		(layer "In11.Cu")
		(net "M_D_CPU0_SA_DQS_DN<7>")
	)
	(segment
		(start 332.415134 -273.581622)
		(end 331.533246 -274.46351)
		(width 0.088646)
		(layer "In11.Cu")
		(net "M_D_CPU0_SA_DQS_DN<7>")
	)
	(segment
		(start 335.922874 -272.32102)
		(end 335.91246 -272.314924)
		(width 0.088646)
		(layer "In11.Cu")
		(net "M_D_CPU0_SA_DQS_DN<7>")
	)
	(segment
		(start 290.622228 -294.816276)
		(end 289.567874 -293.761668)
		(width 0.18288)
		(layer "In11.Cu")
		(net "M_D_CPU0_SA_DQS_DN<7>")
	)
	(segment
		(start 279.590246 -295.4909)
		(end 279.317958 -295.218612)
		(width 0.18288)
		(layer "In11.Cu")
		(net "M_D_CPU0_SA_DQS_DN<7>")
	)
	(segment
		(start 331.533246 -274.802092)
		(end 331.300328 -275.03501)
		(width 0.088646)
		(layer "In11.Cu")
		(net "M_D_CPU0_SA_DQS_DN<7>")
	)
	(segment
		(start 314.225686 -289.294316)
		(end 313.554872 -289.294316)
		(width 0.18288)
		(layer "In11.Cu")
		(net "M_D_CPU0_SA_DQS_DN<7>")
	)
	(segment
		(start 342.116664 -272.314924)
		(end 342.101932 -272.32356)
		(width 0.088646)
		(layer "In11.Cu")
		(net "M_D_CPU0_SA_DQS_DN<7>")
	)
	(segment
		(start 343.056464 -272.314924)
		(end 343.041732 -272.32356)
		(width 0.088646)
		(layer "In11.Cu")
		(net "M_D_CPU0_SA_DQS_DN<7>")
	)
	(segment
		(start 282.079954 -295.219882)
		(end 280.34996 -295.219882)
		(width 0.18288)
		(layer "In11.Cu")
		(net "M_D_CPU0_SA_DQS_DN<7>")
	)
	(segment
		(start 344.936318 -272.314924)
		(end 344.925904 -272.32102)
		(width 0.088646)
		(layer "In11.Cu")
		(net "M_D_CPU0_SA_DQS_DN<7>")
	)
	(segment
		(start 348.255336 -272.639282)
		(end 348.31274 -272.581878)
		(width 0.088646)
		(layer "In11.Cu")
		(net "M_D_CPU0_SA_DQS_DN<7>")
	)
	(segment
		(start 269.104364 -293.091616)
		(end 268.829282 -293.366698)
		(width 0.18288)
		(layer "In11.Cu")
		(net "M_D_CPU0_SA_DQS_DN<7>")
	)
	(segment
		(start 340.237064 -272.314924)
		(end 340.222332 -272.32356)
		(width 0.088646)
		(layer "In11.Cu")
		(net "M_D_CPU0_SA_DQS_DN<7>")
	)
	(segment
		(start 334.983328 -272.32102)
		(end 334.972914 -272.314924)
		(width 0.088646)
		(layer "In11.Cu")
		(net "M_D_CPU0_SA_DQS_DN<7>")
	)
	(segment
		(start 287.491678 -294.200072)
		(end 287.367218 -294.324532)
		(width 0.18288)
		(layer "In11.Cu")
		(net "M_D_CPU0_SA_DQS_DN<7>")
	)
	(segment
		(start 345.321128 -272.32102)
		(end 345.310714 -272.314924)
		(width 0.088646)
		(layer "In11.Cu")
		(net "M_D_CPU0_SA_DQS_DN<7>")
	)
	(arc
		(start 336.478118 -272.314924)
		(mid 336.201305 -272.39076)
		(end 335.922874 -272.32102)
		(width 0.088646)
		(layer "In11.Cu")
		(net "M_D_CPU0_SA_DQS_DN<7>")
	)
	(arc
		(start 343.43086 -272.314924)
		(mid 343.243662 -272.264781)
		(end 343.056464 -272.314924)
		(width 0.088646)
		(layer "In11.Cu")
		(net "M_D_CPU0_SA_DQS_DN<7>")
	)
	(arc
		(start 341.55126 -272.314924)
		(mid 341.364062 -272.264781)
		(end 341.176864 -272.314924)
		(width 0.088646)
		(layer "In11.Cu")
		(net "M_D_CPU0_SA_DQS_DN<7>")
	)
	(arc
		(start 338.357718 -272.314924)
		(mid 338.080905 -272.39076)
		(end 337.802474 -272.32102)
		(width 0.088646)
		(layer "In11.Cu")
		(net "M_D_CPU0_SA_DQS_DN<7>")
	)
	(arc
		(start 343.041732 -272.32356)
		(mid 342.765291 -272.390726)
		(end 342.49106 -272.314924)
		(width 0.088646)
		(layer "In11.Cu")
		(net "M_D_CPU0_SA_DQS_DN<7>")
	)
	(arc
		(start 338.732114 -272.314924)
		(mid 338.544916 -272.264781)
		(end 338.357718 -272.314924)
		(width 0.088646)
		(layer "In11.Cu")
		(net "M_D_CPU0_SA_DQS_DN<7>")
	)
	(arc
		(start 346.25026 -272.314924)
		(mid 346.063062 -272.264781)
		(end 345.875864 -272.314924)
		(width 0.088646)
		(layer "In11.Cu")
		(net "M_D_CPU0_SA_DQS_DN<7>")
	)
	(arc
		(start 347.19006 -272.314924)
		(mid 347.002862 -272.264781)
		(end 346.815664 -272.314924)
		(width 0.088646)
		(layer "In11.Cu")
		(net "M_D_CPU0_SA_DQS_DN<7>")
	)
	(arc
		(start 346.800932 -272.32356)
		(mid 346.524491 -272.390726)
		(end 346.25026 -272.314924)
		(width 0.088646)
		(layer "In11.Cu")
		(net "M_D_CPU0_SA_DQS_DN<7>")
	)
	(arc
		(start 334.03286 -272.314924)
		(mid 333.845662 -272.264781)
		(end 333.658464 -272.314924)
		(width 0.088646)
		(layer "In11.Cu")
		(net "M_D_CPU0_SA_DQS_DN<7>")
	)
	(arc
		(start 333.093314 -272.314924)
		(mid 333.002935 -272.277169)
		(end 332.905862 -272.264124)
		(width 0.088646)
		(layer "In11.Cu")
		(net "M_D_CPU0_SA_DQS_DN<7>")
	)
	(arc
		(start 347.740732 -272.32356)
		(mid 347.464291 -272.390726)
		(end 347.19006 -272.314924)
		(width 0.088646)
		(layer "In11.Cu")
		(net "M_D_CPU0_SA_DQS_DN<7>")
	)
	(arc
		(start 343.981532 -272.32356)
		(mid 343.705091 -272.390726)
		(end 343.43086 -272.314924)
		(width 0.088646)
		(layer "In11.Cu")
		(net "M_D_CPU0_SA_DQS_DN<7>")
	)
	(arc
		(start 344.925904 -272.32102)
		(mid 344.647472 -272.390834)
		(end 344.37066 -272.314924)
		(width 0.088646)
		(layer "In11.Cu")
		(net "M_D_CPU0_SA_DQS_DN<7>")
	)
	(arc
		(start 340.222332 -272.32356)
		(mid 339.945891 -272.390726)
		(end 339.67166 -272.314924)
		(width 0.088646)
		(layer "In11.Cu")
		(net "M_D_CPU0_SA_DQS_DN<7>")
	)
	(arc
		(start 339.297264 -272.314924)
		(mid 339.020705 -272.390633)
		(end 338.742528 -272.32102)
		(width 0.088646)
		(layer "In11.Cu")
		(net "M_D_CPU0_SA_DQS_DN<7>")
	)
	(arc
		(start 334.972914 -272.314924)
		(mid 334.785716 -272.264781)
		(end 334.598518 -272.314924)
		(width 0.088646)
		(layer "In11.Cu")
		(net "M_D_CPU0_SA_DQS_DN<7>")
	)
	(arc
		(start 335.538064 -272.314924)
		(mid 335.261505 -272.390633)
		(end 334.983328 -272.32102)
		(width 0.088646)
		(layer "In11.Cu")
		(net "M_D_CPU0_SA_DQS_DN<7>")
	)
	(arc
		(start 345.875864 -272.314924)
		(mid 345.599305 -272.390633)
		(end 345.321128 -272.32102)
		(width 0.088646)
		(layer "In11.Cu")
		(net "M_D_CPU0_SA_DQS_DN<7>")
	)
	(arc
		(start 337.79206 -272.314924)
		(mid 337.604862 -272.264781)
		(end 337.417664 -272.314924)
		(width 0.088646)
		(layer "In11.Cu")
		(net "M_D_CPU0_SA_DQS_DN<7>")
	)
	(arc
		(start 344.37066 -272.314924)
		(mid 344.183462 -272.264781)
		(end 343.996264 -272.314924)
		(width 0.088646)
		(layer "In11.Cu")
		(net "M_D_CPU0_SA_DQS_DN<7>")
	)
	(arc
		(start 336.852514 -272.314924)
		(mid 336.665316 -272.264781)
		(end 336.478118 -272.314924)
		(width 0.088646)
		(layer "In11.Cu")
		(net "M_D_CPU0_SA_DQS_DN<7>")
	)
	(arc
		(start 339.67166 -272.314924)
		(mid 339.484462 -272.264781)
		(end 339.297264 -272.314924)
		(width 0.088646)
		(layer "In11.Cu")
		(net "M_D_CPU0_SA_DQS_DN<7>")
	)
	(arc
		(start 341.162132 -272.32356)
		(mid 340.885691 -272.390726)
		(end 340.61146 -272.314924)
		(width 0.088646)
		(layer "In11.Cu")
		(net "M_D_CPU0_SA_DQS_DN<7>")
	)
	(arc
		(start 348.31274 -272.581878)
		(mid 348.104457 -272.301532)
		(end 347.755464 -272.314924)
		(width 0.088646)
		(layer "In11.Cu")
		(net "M_D_CPU0_SA_DQS_DN<7>")
	)
	(arc
		(start 334.598518 -272.314924)
		(mid 334.321705 -272.39076)
		(end 334.043274 -272.32102)
		(width 0.088646)
		(layer "In11.Cu")
		(net "M_D_CPU0_SA_DQS_DN<7>")
	)
	(arc
		(start 342.101932 -272.32356)
		(mid 341.825491 -272.390726)
		(end 341.55126 -272.314924)
		(width 0.088646)
		(layer "In11.Cu")
		(net "M_D_CPU0_SA_DQS_DN<7>")
	)
	(arc
		(start 342.49106 -272.314924)
		(mid 342.303862 -272.264781)
		(end 342.116664 -272.314924)
		(width 0.088646)
		(layer "In11.Cu")
		(net "M_D_CPU0_SA_DQS_DN<7>")
	)
	(arc
		(start 333.658464 -272.314924)
		(mid 333.381905 -272.390633)
		(end 333.103728 -272.32102)
		(width 0.088646)
		(layer "In11.Cu")
		(net "M_D_CPU0_SA_DQS_DN<7>")
	)
	(arc
		(start 340.61146 -272.314924)
		(mid 340.424262 -272.264781)
		(end 340.237064 -272.314924)
		(width 0.088646)
		(layer "In11.Cu")
		(net "M_D_CPU0_SA_DQS_DN<7>")
	)
	(arc
		(start 345.310714 -272.314924)
		(mid 345.123516 -272.264781)
		(end 344.936318 -272.314924)
		(width 0.088646)
		(layer "In11.Cu")
		(net "M_D_CPU0_SA_DQS_DN<7>")
	)
	(arc
		(start 335.91246 -272.314924)
		(mid 335.725262 -272.264781)
		(end 335.538064 -272.314924)
		(width 0.088646)
		(layer "In11.Cu")
		(net "M_D_CPU0_SA_DQS_DN<7>")
	)
	(arc
		(start 337.40725 -272.32102)
		(mid 337.129072 -272.390712)
		(end 336.852514 -272.314924)
		(width 0.088646)
		(layer "In11.Cu")
		(net "M_D_CPU0_SA_DQS_DN<7>")
	)
	(segment
		(start 265.6332 -302.030638)
		(end 265.228578 -302.030638)
		(width 0.20066)
		(layer "F.Cu")
		(net "M_D_CPU0_SA_DQS_DN<6>")
	)
	(segment
		(start 268.829282 -302.716692)
		(end 267.724382 -302.716692)
		(width 0.20066)
		(layer "F.Cu")
		(net "M_D_CPU0_SA_DQS_DN<6>")
	)
	(segment
		(start 267.233908 -302.716692)
		(end 266.972796 -302.45558)
		(width 0.20066)
		(layer "F.Cu")
		(net "M_D_CPU0_SA_DQS_DN<6>")
	)
	(segment
		(start 262.511286 -302.29175)
		(end 262.501634 -302.301402)
		(width 0.101854)
		(layer "F.Cu")
		(net "M_D_CPU0_SA_DQS_DN<6>")
	)
	(segment
		(start 265.228578 -302.030638)
		(end 264.967466 -302.29175)
		(width 0.20066)
		(layer "F.Cu")
		(net "M_D_CPU0_SA_DQS_DN<6>")
	)
	(segment
		(start 267.724382 -302.716692)
		(end 267.233908 -302.716692)
		(width 0.20066)
		(layer "F.Cu")
		(net "M_D_CPU0_SA_DQS_DN<6>")
	)
	(segment
		(start 264.967466 -302.29175)
		(end 264.825226 -302.29175)
		(width 0.20066)
		(layer "F.Cu")
		(net "M_D_CPU0_SA_DQS_DN<6>")
	)
	(segment
		(start 264.825226 -302.29175)
		(end 262.74776 -302.29175)
		(width 0.1016)
		(layer "F.Cu")
		(net "M_D_CPU0_SA_DQS_DN<6>")
	)
	(segment
		(start 261.386574 -302.45558)
		(end 260.913372 -302.45558)
		(width 0.20066)
		(layer "F.Cu")
		(net "M_D_CPU0_SA_DQS_DN<6>")
	)
	(segment
		(start 260.913372 -302.45558)
		(end 260.65226 -302.716692)
		(width 0.20066)
		(layer "F.Cu")
		(net "M_D_CPU0_SA_DQS_DN<6>")
	)
	(segment
		(start 262.501634 -302.301402)
		(end 262.50011 -302.301402)
		(width 0.101854)
		(layer "F.Cu")
		(net "M_D_CPU0_SA_DQS_DN<6>")
	)
	(segment
		(start 262.74776 -302.29175)
		(end 262.511286 -302.29175)
		(width 0.101854)
		(layer "F.Cu")
		(net "M_D_CPU0_SA_DQS_DN<6>")
	)
	(segment
		(start 262.048752 -302.033178)
		(end 261.808976 -302.033178)
		(width 0.20066)
		(layer "F.Cu")
		(net "M_D_CPU0_SA_DQS_DN<6>")
	)
	(segment
		(start 261.808976 -302.033178)
		(end 261.386574 -302.45558)
		(width 0.20066)
		(layer "F.Cu")
		(net "M_D_CPU0_SA_DQS_DN<6>")
	)
	(segment
		(start 262.316976 -302.301402)
		(end 262.048752 -302.033178)
		(width 0.20066)
		(layer "F.Cu")
		(net "M_D_CPU0_SA_DQS_DN<6>")
	)
	(segment
		(start 260.65226 -302.716692)
		(end 260.180582 -302.716692)
		(width 0.20066)
		(layer "F.Cu")
		(net "M_D_CPU0_SA_DQS_DN<6>")
	)
	(segment
		(start 266.972796 -302.45558)
		(end 266.269216 -302.45558)
		(width 0.20066)
		(layer "F.Cu")
		(net "M_D_CPU0_SA_DQS_DN<6>")
	)
	(segment
		(start 262.50011 -302.301402)
		(end 262.316976 -302.301402)
		(width 0.20066)
		(layer "F.Cu")
		(net "M_D_CPU0_SA_DQS_DN<6>")
	)
	(segment
		(start 266.269216 -302.45558)
		(end 265.6332 -302.030638)
		(width 0.20066)
		(layer "F.Cu")
		(net "M_D_CPU0_SA_DQS_DN<6>")
	)
	(arc
		(start 347.942916 -276.986492)
		(mid 347.942852 -277.254462)
		(end 347.942662 -277.522432)
		(width 0.20066)
		(layer "F.Cu")
		(net "M_D_CPU0_SA_DQS_DN<6>")
	)
	(segment
		(start 283.46273 -307.128672)
		(end 282.965398 -307.128672)
		(width 0.18288)
		(layer "In11.Cu")
		(net "M_D_CPU0_SA_DQS_DN<6>")
	)
	(segment
		(start 284.104842 -307.3908)
		(end 283.724858 -307.3908)
		(width 0.18288)
		(layer "In11.Cu")
		(net "M_D_CPU0_SA_DQS_DN<6>")
	)
	(segment
		(start 291.829744 -307.949346)
		(end 288.434526 -307.949346)
		(width 0.18288)
		(layer "In11.Cu")
		(net "M_D_CPU0_SA_DQS_DN<6>")
	)
	(segment
		(start 312.63463 -300.298358)
		(end 311.91073 -300.298358)
		(width 0.18288)
		(layer "In11.Cu")
		(net "M_D_CPU0_SA_DQS_DN<6>")
	)
	(segment
		(start 316.482222 -296.299636)
		(end 316.482222 -298.06646)
		(width 0.18288)
		(layer "In11.Cu")
		(net "M_D_CPU0_SA_DQS_DN<6>")
	)
	(segment
		(start 275.844508 -307.675788)
		(end 275.589746 -307.061616)
		(width 0.18288)
		(layer "In11.Cu")
		(net "M_D_CPU0_SA_DQS_DN<6>")
	)
	(segment
		(start 287.598358 -307.113178)
		(end 284.382464 -307.113178)
		(width 0.18288)
		(layer "In11.Cu")
		(net "M_D_CPU0_SA_DQS_DN<6>")
	)
	(segment
		(start 275.589746 -307.061616)
		(end 275.589746 -305.810666)
		(width 0.18288)
		(layer "In11.Cu")
		(net "M_D_CPU0_SA_DQS_DN<6>")
	)
	(segment
		(start 276.250908 -308.082188)
		(end 275.844508 -307.675788)
		(width 0.18288)
		(layer "In11.Cu")
		(net "M_D_CPU0_SA_DQS_DN<6>")
	)
	(segment
		(start 311.78627 -300.422818)
		(end 311.23763 -300.422818)
		(width 0.18288)
		(layer "In11.Cu")
		(net "M_D_CPU0_SA_DQS_DN<6>")
	)
	(segment
		(start 292.887146 -307.321966)
		(end 292.457124 -307.321966)
		(width 0.18288)
		(layer "In11.Cu")
		(net "M_D_CPU0_SA_DQS_DN<6>")
	)
	(segment
		(start 341.176864 -277.198074)
		(end 341.162132 -277.20671)
		(width 0.088646)
		(layer "In11.Cu")
		(net "M_D_CPU0_SA_DQS_DN<6>")
	)
	(segment
		(start 314.596018 -299.47616)
		(end 314.33389 -299.738288)
		(width 0.18288)
		(layer "In11.Cu")
		(net "M_D_CPU0_SA_DQS_DN<6>")
	)
	(segment
		(start 282.123134 -307.970936)
		(end 280.269696 -307.970936)
		(width 0.18288)
		(layer "In11.Cu")
		(net "M_D_CPU0_SA_DQS_DN<6>")
	)
	(segment
		(start 279.363932 -307.98008)
		(end 279.351232 -307.98008)
		(width 0.18288)
		(layer "In11.Cu")
		(net "M_D_CPU0_SA_DQS_DN<6>")
	)
	(segment
		(start 336.852514 -277.198074)
		(end 336.852006 -277.198328)
		(width 0.088646)
		(layer "In11.Cu")
		(net "M_D_CPU0_SA_DQS_DN<6>")
	)
	(segment
		(start 336.862928 -277.20417)
		(end 336.852514 -277.198074)
		(width 0.088646)
		(layer "In11.Cu")
		(net "M_D_CPU0_SA_DQS_DN<6>")
	)
	(segment
		(start 315.072522 -299.47616)
		(end 314.596018 -299.47616)
		(width 0.18288)
		(layer "In11.Cu")
		(net "M_D_CPU0_SA_DQS_DN<6>")
	)
	(segment
		(start 278.783796 -307.957728)
		(end 278.157178 -308.584346)
		(width 0.18288)
		(layer "In11.Cu")
		(net "M_D_CPU0_SA_DQS_DN<6>")
	)
	(segment
		(start 294.435022 -307.998114)
		(end 293.563294 -307.998114)
		(width 0.18288)
		(layer "In11.Cu")
		(net "M_D_CPU0_SA_DQS_DN<6>")
	)
	(segment
		(start 331.498448 -281.424126)
		(end 330.618592 -281.424126)
		(width 0.18288)
		(layer "In11.Cu")
		(net "M_D_CPU0_SA_DQS_DN<6>")
	)
	(segment
		(start 344.936064 -277.198074)
		(end 344.921332 -277.20671)
		(width 0.088646)
		(layer "In11.Cu")
		(net "M_D_CPU0_SA_DQS_DN<6>")
	)
	(segment
		(start 313.624976 -299.49267)
		(end 313.440318 -299.49267)
		(width 0.18288)
		(layer "In11.Cu")
		(net "M_D_CPU0_SA_DQS_DN<6>")
	)
	(segment
		(start 277.462488 -308.584346)
		(end 276.250908 -308.082188)
		(width 0.18288)
		(layer "In11.Cu")
		(net "M_D_CPU0_SA_DQS_DN<6>")
	)
	(segment
		(start 340.237064 -277.198074)
		(end 340.222332 -277.20671)
		(width 0.088646)
		(layer "In11.Cu")
		(net "M_D_CPU0_SA_DQS_DN<6>")
	)
	(segment
		(start 305.141122 -302.145446)
		(end 303.807368 -303.4792)
		(width 0.18288)
		(layer "In11.Cu")
		(net "M_D_CPU0_SA_DQS_DN<6>")
	)
	(segment
		(start 275.589746 -305.810666)
		(end 274.477226 -304.698146)
		(width 0.18288)
		(layer "In11.Cu")
		(net "M_D_CPU0_SA_DQS_DN<6>")
	)
	(segment
		(start 283.724858 -307.3908)
		(end 283.46273 -307.128672)
		(width 0.18288)
		(layer "In11.Cu")
		(net "M_D_CPU0_SA_DQS_DN<6>")
	)
	(segment
		(start 338.742528 -277.20417)
		(end 338.732114 -277.198074)
		(width 0.088646)
		(layer "In11.Cu")
		(net "M_D_CPU0_SA_DQS_DN<6>")
	)
	(segment
		(start 337.802474 -277.20417)
		(end 337.79206 -277.198074)
		(width 0.088646)
		(layer "In11.Cu")
		(net "M_D_CPU0_SA_DQS_DN<6>")
	)
	(segment
		(start 309.765446 -300.590966)
		(end 309.521098 -300.346618)
		(width 0.18288)
		(layer "In11.Cu")
		(net "M_D_CPU0_SA_DQS_DN<6>")
	)
	(segment
		(start 274.477226 -304.698146)
		(end 273.881596 -304.698146)
		(width 0.18288)
		(layer "In11.Cu")
		(net "M_D_CPU0_SA_DQS_DN<6>")
	)
	(segment
		(start 342.116664 -277.198074)
		(end 342.101932 -277.20671)
		(width 0.088646)
		(layer "In11.Cu")
		(net "M_D_CPU0_SA_DQS_DN<6>")
	)
	(segment
		(start 343.056464 -277.198074)
		(end 343.041732 -277.20671)
		(width 0.088646)
		(layer "In11.Cu")
		(net "M_D_CPU0_SA_DQS_DN<6>")
	)
	(segment
		(start 311.11317 -300.298358)
		(end 310.54675 -300.298358)
		(width 0.18288)
		(layer "In11.Cu")
		(net "M_D_CPU0_SA_DQS_DN<6>")
	)
	(segment
		(start 310.254142 -300.590966)
		(end 309.765446 -300.590966)
		(width 0.18288)
		(layer "In11.Cu")
		(net "M_D_CPU0_SA_DQS_DN<6>")
	)
	(segment
		(start 297.917108 -307.104034)
		(end 297.04157 -307.979572)
		(width 0.18288)
		(layer "In11.Cu")
		(net "M_D_CPU0_SA_DQS_DN<6>")
	)
	(segment
		(start 313.440318 -299.49267)
		(end 312.63463 -300.298358)
		(width 0.18288)
		(layer "In11.Cu")
		(net "M_D_CPU0_SA_DQS_DN<6>")
	)
	(segment
		(start 279.999694 -308.240938)
		(end 279.62479 -308.240938)
		(width 0.18288)
		(layer "In11.Cu")
		(net "M_D_CPU0_SA_DQS_DN<6>")
	)
	(segment
		(start 332.579726 -280.05659)
		(end 332.579726 -280.258012)
		(width 0.088646)
		(layer "In11.Cu")
		(net "M_D_CPU0_SA_DQS_DN<6>")
	)
	(segment
		(start 331.731874 -281.105864)
		(end 331.731874 -281.1907)
		(width 0.088646)
		(layer "In11.Cu")
		(net "M_D_CPU0_SA_DQS_DN<6>")
	)
	(segment
		(start 309.521098 -300.346618)
		(end 308.81066 -300.346618)
		(width 0.18288)
		(layer "In11.Cu")
		(net "M_D_CPU0_SA_DQS_DN<6>")
	)
	(segment
		(start 311.91073 -300.298358)
		(end 311.78627 -300.422818)
		(width 0.18288)
		(layer "In11.Cu")
		(net "M_D_CPU0_SA_DQS_DN<6>")
	)
	(segment
		(start 303.807368 -304.413412)
		(end 302.981614 -305.239166)
		(width 0.18288)
		(layer "In11.Cu")
		(net "M_D_CPU0_SA_DQS_DN<6>")
	)
	(segment
		(start 320.204084 -292.577774)
		(end 316.482222 -296.299636)
		(width 0.18288)
		(layer "In11.Cu")
		(net "M_D_CPU0_SA_DQS_DN<6>")
	)
	(segment
		(start 310.54675 -300.298358)
		(end 310.254142 -300.590966)
		(width 0.18288)
		(layer "In11.Cu")
		(net "M_D_CPU0_SA_DQS_DN<6>")
	)
	(segment
		(start 308.81066 -300.346618)
		(end 307.796692 -301.360586)
		(width 0.18288)
		(layer "In11.Cu")
		(net "M_D_CPU0_SA_DQS_DN<6>")
	)
	(segment
		(start 298.519596 -307.104034)
		(end 297.917108 -307.104034)
		(width 0.18288)
		(layer "In11.Cu")
		(net "M_D_CPU0_SA_DQS_DN<6>")
	)
	(segment
		(start 279.32888 -307.957728)
		(end 278.783796 -307.957728)
		(width 0.18288)
		(layer "In11.Cu")
		(net "M_D_CPU0_SA_DQS_DN<6>")
	)
	(segment
		(start 288.434526 -307.949346)
		(end 287.598358 -307.113178)
		(width 0.18288)
		(layer "In11.Cu")
		(net "M_D_CPU0_SA_DQS_DN<6>")
	)
	(segment
		(start 293.563294 -307.998114)
		(end 292.887146 -307.321966)
		(width 0.18288)
		(layer "In11.Cu")
		(net "M_D_CPU0_SA_DQS_DN<6>")
	)
	(segment
		(start 330.618592 -281.424126)
		(end 320.204084 -291.838634)
		(width 0.18288)
		(layer "In11.Cu")
		(net "M_D_CPU0_SA_DQS_DN<6>")
	)
	(segment
		(start 316.482222 -298.06646)
		(end 316.094364 -298.454318)
		(width 0.18288)
		(layer "In11.Cu")
		(net "M_D_CPU0_SA_DQS_DN<6>")
	)
	(segment
		(start 273.881596 -304.698146)
		(end 273.25066 -304.43678)
		(width 0.18288)
		(layer "In11.Cu")
		(net "M_D_CPU0_SA_DQS_DN<6>")
	)
	(segment
		(start 347.755464 -277.198074)
		(end 347.740732 -277.20671)
		(width 0.088646)
		(layer "In11.Cu")
		(net "M_D_CPU0_SA_DQS_DN<6>")
	)
	(segment
		(start 336.47761 -277.198328)
		(end 336.477356 -277.19782)
		(width 0.088646)
		(layer "In11.Cu")
		(net "M_D_CPU0_SA_DQS_DN<6>")
	)
	(segment
		(start 315.706252 -299.018452)
		(end 315.53023 -299.018452)
		(width 0.18288)
		(layer "In11.Cu")
		(net "M_D_CPU0_SA_DQS_DN<6>")
	)
	(segment
		(start 273.25066 -304.43678)
		(end 272.462752 -303.648872)
		(width 0.18288)
		(layer "In11.Cu")
		(net "M_D_CPU0_SA_DQS_DN<6>")
	)
	(segment
		(start 346.815664 -277.198074)
		(end 346.800932 -277.20671)
		(width 0.088646)
		(layer "In11.Cu")
		(net "M_D_CPU0_SA_DQS_DN<6>")
	)
	(segment
		(start 298.806362 -307.3908)
		(end 298.519596 -307.104034)
		(width 0.18288)
		(layer "In11.Cu")
		(net "M_D_CPU0_SA_DQS_DN<6>")
	)
	(segment
		(start 282.965398 -307.128672)
		(end 282.123134 -307.970936)
		(width 0.18288)
		(layer "In11.Cu")
		(net "M_D_CPU0_SA_DQS_DN<6>")
	)
	(segment
		(start 334.11414 -277.93188)
		(end 333.707232 -278.338788)
		(width 0.088646)
		(layer "In11.Cu")
		(net "M_D_CPU0_SA_DQS_DN<6>")
	)
	(segment
		(start 306.730654 -302.145446)
		(end 305.141122 -302.145446)
		(width 0.18288)
		(layer "In11.Cu")
		(net "M_D_CPU0_SA_DQS_DN<6>")
	)
	(segment
		(start 295.382188 -307.979572)
		(end 295.120822 -308.240938)
		(width 0.18288)
		(layer "In11.Cu")
		(net "M_D_CPU0_SA_DQS_DN<6>")
	)
	(segment
		(start 302.426116 -305.239166)
		(end 300.523402 -307.14188)
		(width 0.18288)
		(layer "In11.Cu")
		(net "M_D_CPU0_SA_DQS_DN<6>")
	)
	(segment
		(start 299.501306 -307.14188)
		(end 299.252386 -307.3908)
		(width 0.18288)
		(layer "In11.Cu")
		(net "M_D_CPU0_SA_DQS_DN<6>")
	)
	(segment
		(start 279.351232 -307.98008)
		(end 279.32888 -307.957728)
		(width 0.18288)
		(layer "In11.Cu")
		(net "M_D_CPU0_SA_DQS_DN<6>")
	)
	(segment
		(start 307.796692 -301.360586)
		(end 307.515514 -301.360586)
		(width 0.18288)
		(layer "In11.Cu")
		(net "M_D_CPU0_SA_DQS_DN<6>")
	)
	(segment
		(start 334.853534 -277.93188)
		(end 334.11414 -277.93188)
		(width 0.088646)
		(layer "In11.Cu")
		(net "M_D_CPU0_SA_DQS_DN<6>")
	)
	(segment
		(start 279.62479 -308.240938)
		(end 279.363932 -307.98008)
		(width 0.18288)
		(layer "In11.Cu")
		(net "M_D_CPU0_SA_DQS_DN<6>")
	)
	(segment
		(start 348.255336 -277.522432)
		(end 348.31274 -277.465028)
		(width 0.088646)
		(layer "In11.Cu")
		(net "M_D_CPU0_SA_DQS_DN<6>")
	)
	(segment
		(start 295.120822 -308.240938)
		(end 294.677846 -308.240938)
		(width 0.18288)
		(layer "In11.Cu")
		(net "M_D_CPU0_SA_DQS_DN<6>")
	)
	(segment
		(start 333.707232 -278.929084)
		(end 332.579726 -280.05659)
		(width 0.088646)
		(layer "In11.Cu")
		(net "M_D_CPU0_SA_DQS_DN<6>")
	)
	(segment
		(start 299.252386 -307.3908)
		(end 298.806362 -307.3908)
		(width 0.18288)
		(layer "In11.Cu")
		(net "M_D_CPU0_SA_DQS_DN<6>")
	)
	(segment
		(start 336.147156 -277.337012)
		(end 335.652872 -277.667466)
		(width 0.088646)
		(layer "In11.Cu")
		(net "M_D_CPU0_SA_DQS_DN<6>")
	)
	(segment
		(start 316.094364 -298.63034)
		(end 315.706252 -299.018452)
		(width 0.18288)
		(layer "In11.Cu")
		(net "M_D_CPU0_SA_DQS_DN<6>")
	)
	(segment
		(start 307.515514 -301.360586)
		(end 306.730654 -302.145446)
		(width 0.18288)
		(layer "In11.Cu")
		(net "M_D_CPU0_SA_DQS_DN<6>")
	)
	(segment
		(start 292.457124 -307.321966)
		(end 291.829744 -307.949346)
		(width 0.18288)
		(layer "In11.Cu")
		(net "M_D_CPU0_SA_DQS_DN<6>")
	)
	(segment
		(start 270.560038 -302.859948)
		(end 269.857474 -302.859948)
		(width 0.18288)
		(layer "In11.Cu")
		(net "M_D_CPU0_SA_DQS_DN<6>")
	)
	(segment
		(start 313.870594 -299.738288)
		(end 313.624976 -299.49267)
		(width 0.18288)
		(layer "In11.Cu")
		(net "M_D_CPU0_SA_DQS_DN<6>")
	)
	(segment
		(start 302.981614 -305.239166)
		(end 302.426116 -305.239166)
		(width 0.18288)
		(layer "In11.Cu")
		(net "M_D_CPU0_SA_DQS_DN<6>")
	)
	(segment
		(start 294.677846 -308.240938)
		(end 294.435022 -307.998114)
		(width 0.18288)
		(layer "In11.Cu")
		(net "M_D_CPU0_SA_DQS_DN<6>")
	)
	(segment
		(start 331.731874 -281.1907)
		(end 331.498448 -281.424126)
		(width 0.18288)
		(layer "In11.Cu")
		(net "M_D_CPU0_SA_DQS_DN<6>")
	)
	(segment
		(start 272.462752 -303.648872)
		(end 270.560038 -302.859948)
		(width 0.18288)
		(layer "In11.Cu")
		(net "M_D_CPU0_SA_DQS_DN<6>")
	)
	(segment
		(start 278.157178 -308.584346)
		(end 277.462488 -308.584346)
		(width 0.18288)
		(layer "In11.Cu")
		(net "M_D_CPU0_SA_DQS_DN<6>")
	)
	(segment
		(start 314.33389 -299.738288)
		(end 313.870594 -299.738288)
		(width 0.18288)
		(layer "In11.Cu")
		(net "M_D_CPU0_SA_DQS_DN<6>")
	)
	(segment
		(start 303.807368 -303.4792)
		(end 303.807368 -304.413412)
		(width 0.18288)
		(layer "In11.Cu")
		(net "M_D_CPU0_SA_DQS_DN<6>")
	)
	(segment
		(start 343.996264 -277.198074)
		(end 343.981532 -277.20671)
		(width 0.088646)
		(layer "In11.Cu")
		(net "M_D_CPU0_SA_DQS_DN<6>")
	)
	(segment
		(start 315.53023 -299.018452)
		(end 315.072522 -299.47616)
		(width 0.18288)
		(layer "In11.Cu")
		(net "M_D_CPU0_SA_DQS_DN<6>")
	)
	(segment
		(start 347.942662 -277.522432)
		(end 348.255336 -277.522432)
		(width 0.088646)
		(layer "In11.Cu")
		(net "M_D_CPU0_SA_DQS_DN<6>")
	)
	(segment
		(start 316.094364 -298.454318)
		(end 316.094364 -298.63034)
		(width 0.18288)
		(layer "In11.Cu")
		(net "M_D_CPU0_SA_DQS_DN<6>")
	)
	(segment
		(start 332.579726 -280.258012)
		(end 331.731874 -281.105864)
		(width 0.088646)
		(layer "In11.Cu")
		(net "M_D_CPU0_SA_DQS_DN<6>")
	)
	(segment
		(start 333.707232 -278.338788)
		(end 333.707232 -278.929084)
		(width 0.088646)
		(layer "In11.Cu")
		(net "M_D_CPU0_SA_DQS_DN<6>")
	)
	(segment
		(start 269.090648 -302.455326)
		(end 268.829282 -302.716692)
		(width 0.18288)
		(layer "In11.Cu")
		(net "M_D_CPU0_SA_DQS_DN<6>")
	)
	(segment
		(start 269.452852 -302.455326)
		(end 269.090648 -302.455326)
		(width 0.18288)
		(layer "In11.Cu")
		(net "M_D_CPU0_SA_DQS_DN<6>")
	)
	(segment
		(start 284.382464 -307.113178)
		(end 284.104842 -307.3908)
		(width 0.18288)
		(layer "In11.Cu")
		(net "M_D_CPU0_SA_DQS_DN<6>")
	)
	(segment
		(start 280.269696 -307.970936)
		(end 279.999694 -308.240938)
		(width 0.18288)
		(layer "In11.Cu")
		(net "M_D_CPU0_SA_DQS_DN<6>")
	)
	(segment
		(start 320.204084 -291.838634)
		(end 320.204084 -292.577774)
		(width 0.18288)
		(layer "In11.Cu")
		(net "M_D_CPU0_SA_DQS_DN<6>")
	)
	(segment
		(start 300.523402 -307.14188)
		(end 299.501306 -307.14188)
		(width 0.18288)
		(layer "In11.Cu")
		(net "M_D_CPU0_SA_DQS_DN<6>")
	)
	(segment
		(start 297.04157 -307.979572)
		(end 295.382188 -307.979572)
		(width 0.18288)
		(layer "In11.Cu")
		(net "M_D_CPU0_SA_DQS_DN<6>")
	)
	(segment
		(start 311.23763 -300.422818)
		(end 311.11317 -300.298358)
		(width 0.18288)
		(layer "In11.Cu")
		(net "M_D_CPU0_SA_DQS_DN<6>")
	)
	(segment
		(start 269.857474 -302.859948)
		(end 269.452852 -302.455326)
		(width 0.18288)
		(layer "In11.Cu")
		(net "M_D_CPU0_SA_DQS_DN<6>")
	)
	(arc
		(start 344.37066 -277.198074)
		(mid 344.183462 -277.147931)
		(end 343.996264 -277.198074)
		(width 0.088646)
		(layer "In11.Cu")
		(net "M_D_CPU0_SA_DQS_DN<6>")
	)
	(arc
		(start 335.652872 -277.667466)
		(mid 335.634263 -277.679812)
		(end 335.615788 -277.692358)
		(width 0.088646)
		(layer "In11.Cu")
		(net "M_D_CPU0_SA_DQS_DN<6>")
	)
	(arc
		(start 341.55126 -277.198074)
		(mid 341.364062 -277.147931)
		(end 341.176864 -277.198074)
		(width 0.088646)
		(layer "In11.Cu")
		(net "M_D_CPU0_SA_DQS_DN<6>")
	)
	(arc
		(start 343.981532 -277.20671)
		(mid 343.705057 -277.27403)
		(end 343.43086 -277.198074)
		(width 0.088646)
		(layer "In11.Cu")
		(net "M_D_CPU0_SA_DQS_DN<6>")
	)
	(arc
		(start 343.041732 -277.20671)
		(mid 342.765257 -277.27403)
		(end 342.49106 -277.198074)
		(width 0.088646)
		(layer "In11.Cu")
		(net "M_D_CPU0_SA_DQS_DN<6>")
	)
	(arc
		(start 346.25026 -277.198074)
		(mid 346.063062 -277.147931)
		(end 345.875864 -277.198074)
		(width 0.088646)
		(layer "In11.Cu")
		(net "M_D_CPU0_SA_DQS_DN<6>")
	)
	(arc
		(start 336.328004 -277.257764)
		(mid 336.234098 -277.289438)
		(end 336.147156 -277.337012)
		(width 0.088646)
		(layer "In11.Cu")
		(net "M_D_CPU0_SA_DQS_DN<6>")
	)
	(arc
		(start 345.875864 -277.198074)
		(mid 345.593162 -277.27385)
		(end 345.31046 -277.198074)
		(width 0.088646)
		(layer "In11.Cu")
		(net "M_D_CPU0_SA_DQS_DN<6>")
	)
	(arc
		(start 341.162132 -277.20671)
		(mid 340.885657 -277.27403)
		(end 340.61146 -277.198074)
		(width 0.088646)
		(layer "In11.Cu")
		(net "M_D_CPU0_SA_DQS_DN<6>")
	)
	(arc
		(start 348.31274 -277.465028)
		(mid 348.104418 -277.184874)
		(end 347.755464 -277.198074)
		(width 0.088646)
		(layer "In11.Cu")
		(net "M_D_CPU0_SA_DQS_DN<6>")
	)
	(arc
		(start 337.417664 -277.198074)
		(mid 337.141105 -277.273817)
		(end 336.862928 -277.20417)
		(width 0.088646)
		(layer "In11.Cu")
		(net "M_D_CPU0_SA_DQS_DN<6>")
	)
	(arc
		(start 338.732114 -277.198074)
		(mid 338.544916 -277.147931)
		(end 338.357718 -277.198074)
		(width 0.088646)
		(layer "In11.Cu")
		(net "M_D_CPU0_SA_DQS_DN<6>")
	)
	(arc
		(start 336.477356 -277.19782)
		(mid 336.404826 -277.233138)
		(end 336.328004 -277.257764)
		(width 0.088646)
		(layer "In11.Cu")
		(net "M_D_CPU0_SA_DQS_DN<6>")
	)
	(arc
		(start 347.740732 -277.20671)
		(mid 347.464257 -277.27403)
		(end 347.19006 -277.198074)
		(width 0.088646)
		(layer "In11.Cu")
		(net "M_D_CPU0_SA_DQS_DN<6>")
	)
	(arc
		(start 335.615788 -277.692358)
		(mid 335.253022 -277.870549)
		(end 334.853534 -277.93188)
		(width 0.088646)
		(layer "In11.Cu")
		(net "M_D_CPU0_SA_DQS_DN<6>")
	)
	(arc
		(start 340.222332 -277.20671)
		(mid 339.945857 -277.27403)
		(end 339.67166 -277.198074)
		(width 0.088646)
		(layer "In11.Cu")
		(net "M_D_CPU0_SA_DQS_DN<6>")
	)
	(arc
		(start 343.43086 -277.198074)
		(mid 343.243662 -277.147931)
		(end 343.056464 -277.198074)
		(width 0.088646)
		(layer "In11.Cu")
		(net "M_D_CPU0_SA_DQS_DN<6>")
	)
	(arc
		(start 338.357718 -277.198074)
		(mid 338.080905 -277.273944)
		(end 337.802474 -277.20417)
		(width 0.088646)
		(layer "In11.Cu")
		(net "M_D_CPU0_SA_DQS_DN<6>")
	)
	(arc
		(start 342.49106 -277.198074)
		(mid 342.303862 -277.147931)
		(end 342.116664 -277.198074)
		(width 0.088646)
		(layer "In11.Cu")
		(net "M_D_CPU0_SA_DQS_DN<6>")
	)
	(arc
		(start 347.19006 -277.198074)
		(mid 347.002862 -277.147931)
		(end 346.815664 -277.198074)
		(width 0.088646)
		(layer "In11.Cu")
		(net "M_D_CPU0_SA_DQS_DN<6>")
	)
	(arc
		(start 336.852006 -277.198328)
		(mid 336.664808 -277.148185)
		(end 336.47761 -277.198328)
		(width 0.088646)
		(layer "In11.Cu")
		(net "M_D_CPU0_SA_DQS_DN<6>")
	)
	(arc
		(start 345.31046 -277.198074)
		(mid 345.123262 -277.147931)
		(end 344.936064 -277.198074)
		(width 0.088646)
		(layer "In11.Cu")
		(net "M_D_CPU0_SA_DQS_DN<6>")
	)
	(arc
		(start 337.79206 -277.198074)
		(mid 337.604862 -277.147931)
		(end 337.417664 -277.198074)
		(width 0.088646)
		(layer "In11.Cu")
		(net "M_D_CPU0_SA_DQS_DN<6>")
	)
	(arc
		(start 339.67166 -277.198074)
		(mid 339.484462 -277.147931)
		(end 339.297264 -277.198074)
		(width 0.088646)
		(layer "In11.Cu")
		(net "M_D_CPU0_SA_DQS_DN<6>")
	)
	(arc
		(start 344.921332 -277.20671)
		(mid 344.644857 -277.27403)
		(end 344.37066 -277.198074)
		(width 0.088646)
		(layer "In11.Cu")
		(net "M_D_CPU0_SA_DQS_DN<6>")
	)
	(arc
		(start 346.800932 -277.20671)
		(mid 346.524457 -277.27403)
		(end 346.25026 -277.198074)
		(width 0.088646)
		(layer "In11.Cu")
		(net "M_D_CPU0_SA_DQS_DN<6>")
	)
	(arc
		(start 342.101932 -277.20671)
		(mid 341.825457 -277.27403)
		(end 341.55126 -277.198074)
		(width 0.088646)
		(layer "In11.Cu")
		(net "M_D_CPU0_SA_DQS_DN<6>")
	)
	(arc
		(start 339.297264 -277.198074)
		(mid 339.020705 -277.273817)
		(end 338.742528 -277.20417)
		(width 0.088646)
		(layer "In11.Cu")
		(net "M_D_CPU0_SA_DQS_DN<6>")
	)
	(arc
		(start 340.61146 -277.198074)
		(mid 340.424262 -277.147931)
		(end 340.237064 -277.198074)
		(width 0.088646)
		(layer "In11.Cu")
		(net "M_D_CPU0_SA_DQS_DN<6>")
	)
	(segment
		(start 267.724382 -312.066686)
		(end 267.233908 -312.066686)
		(width 0.20066)
		(layer "F.Cu")
		(net "M_D_CPU0_SA_DQS_DN<5>")
	)
	(segment
		(start 265.6332 -311.380632)
		(end 265.228578 -311.380632)
		(width 0.20066)
		(layer "F.Cu")
		(net "M_D_CPU0_SA_DQS_DN<5>")
	)
	(segment
		(start 262.048752 -311.383172)
		(end 261.808976 -311.383172)
		(width 0.20066)
		(layer "F.Cu")
		(net "M_D_CPU0_SA_DQS_DN<5>")
	)
	(segment
		(start 266.972796 -311.805574)
		(end 266.269216 -311.805574)
		(width 0.20066)
		(layer "F.Cu")
		(net "M_D_CPU0_SA_DQS_DN<5>")
	)
	(segment
		(start 265.228578 -311.380632)
		(end 264.967466 -311.641744)
		(width 0.20066)
		(layer "F.Cu")
		(net "M_D_CPU0_SA_DQS_DN<5>")
	)
	(segment
		(start 261.386574 -311.805574)
		(end 260.913372 -311.805574)
		(width 0.20066)
		(layer "F.Cu")
		(net "M_D_CPU0_SA_DQS_DN<5>")
	)
	(segment
		(start 267.233908 -312.066686)
		(end 266.972796 -311.805574)
		(width 0.20066)
		(layer "F.Cu")
		(net "M_D_CPU0_SA_DQS_DN<5>")
	)
	(segment
		(start 266.269216 -311.805574)
		(end 265.6332 -311.380632)
		(width 0.20066)
		(layer "F.Cu")
		(net "M_D_CPU0_SA_DQS_DN<5>")
	)
	(segment
		(start 262.74776 -311.641744)
		(end 262.511286 -311.641744)
		(width 0.101854)
		(layer "F.Cu")
		(net "M_D_CPU0_SA_DQS_DN<5>")
	)
	(segment
		(start 261.808976 -311.383172)
		(end 261.386574 -311.805574)
		(width 0.20066)
		(layer "F.Cu")
		(net "M_D_CPU0_SA_DQS_DN<5>")
	)
	(segment
		(start 260.913372 -311.805574)
		(end 260.65226 -312.066686)
		(width 0.20066)
		(layer "F.Cu")
		(net "M_D_CPU0_SA_DQS_DN<5>")
	)
	(segment
		(start 268.829282 -312.066686)
		(end 267.724382 -312.066686)
		(width 0.20066)
		(layer "F.Cu")
		(net "M_D_CPU0_SA_DQS_DN<5>")
	)
	(segment
		(start 262.501634 -311.651396)
		(end 262.50011 -311.651396)
		(width 0.101854)
		(layer "F.Cu")
		(net "M_D_CPU0_SA_DQS_DN<5>")
	)
	(segment
		(start 262.511286 -311.641744)
		(end 262.501634 -311.651396)
		(width 0.101854)
		(layer "F.Cu")
		(net "M_D_CPU0_SA_DQS_DN<5>")
	)
	(segment
		(start 262.316976 -311.651396)
		(end 262.048752 -311.383172)
		(width 0.20066)
		(layer "F.Cu")
		(net "M_D_CPU0_SA_DQS_DN<5>")
	)
	(segment
		(start 262.50011 -311.651396)
		(end 262.316976 -311.651396)
		(width 0.20066)
		(layer "F.Cu")
		(net "M_D_CPU0_SA_DQS_DN<5>")
	)
	(segment
		(start 264.967466 -311.641744)
		(end 264.825226 -311.641744)
		(width 0.20066)
		(layer "F.Cu")
		(net "M_D_CPU0_SA_DQS_DN<5>")
	)
	(segment
		(start 264.825226 -311.641744)
		(end 262.74776 -311.641744)
		(width 0.1016)
		(layer "F.Cu")
		(net "M_D_CPU0_SA_DQS_DN<5>")
	)
	(segment
		(start 260.65226 -312.066686)
		(end 260.180582 -312.066686)
		(width 0.20066)
		(layer "F.Cu")
		(net "M_D_CPU0_SA_DQS_DN<5>")
	)
	(arc
		(start 345.593162 -274.54479)
		(mid 345.593225 -274.81276)
		(end 345.593416 -275.08073)
		(width 0.20066)
		(layer "F.Cu")
		(net "M_D_CPU0_SA_DQS_DN<5>")
	)
	(segment
		(start 333.580232 -277.25751)
		(end 333.337662 -277.50008)
		(width 0.088646)
		(layer "In6.Cu")
		(net "M_D_CPU0_SA_DQS_DN<5>")
	)
	(segment
		(start 269.72641 -312.047636)
		(end 269.465044 -311.78627)
		(width 0.18288)
		(layer "In6.Cu")
		(net "M_D_CPU0_SA_DQS_DN<5>")
	)
	(segment
		(start 293.349426 -308.588156)
		(end 292.838124 -308.588156)
		(width 0.18288)
		(layer "In6.Cu")
		(net "M_D_CPU0_SA_DQS_DN<5>")
	)
	(segment
		(start 343.902792 -274.757388)
		(end 343.90076 -274.756372)
		(width 0.088646)
		(layer "In6.Cu")
		(net "M_D_CPU0_SA_DQS_DN<5>")
	)
	(segment
		(start 299.564552 -305.41214)
		(end 299.284898 -305.691794)
		(width 0.18288)
		(layer "In6.Cu")
		(net "M_D_CPU0_SA_DQS_DN<5>")
	)
	(segment
		(start 311.31637 -298.447968)
		(end 310.912002 -298.0436)
		(width 0.18288)
		(layer "In6.Cu")
		(net "M_D_CPU0_SA_DQS_DN<5>")
	)
	(segment
		(start 335.068164 -276.384258)
		(end 335.059274 -276.389338)
		(width 0.088646)
		(layer "In6.Cu")
		(net "M_D_CPU0_SA_DQS_DN<5>")
	)
	(segment
		(start 344.870786 -275.387816)
		(end 344.842846 -275.404072)
		(width 0.088646)
		(layer "In6.Cu")
		(net "M_D_CPU0_SA_DQS_DN<5>")
	)
	(segment
		(start 342.036146 -274.765008)
		(end 342.021414 -274.756372)
		(width 0.088646)
		(layer "In6.Cu")
		(net "M_D_CPU0_SA_DQS_DN<5>")
	)
	(segment
		(start 334.59801 -277.198328)
		(end 334.583278 -277.206964)
		(width 0.088646)
		(layer "In6.Cu")
		(net "M_D_CPU0_SA_DQS_DN<5>")
	)
	(segment
		(start 344.842846 -275.404072)
		(end 344.840814 -275.405088)
		(width 0.088646)
		(layer "In6.Cu")
		(net "M_D_CPU0_SA_DQS_DN<5>")
	)
	(segment
		(start 341.096346 -274.765008)
		(end 341.081614 -274.756372)
		(width 0.088646)
		(layer "In6.Cu")
		(net "M_D_CPU0_SA_DQS_DN<5>")
	)
	(segment
		(start 343.90076 -274.756372)
		(end 343.901014 -274.756372)
		(width 0.088646)
		(layer "In6.Cu")
		(net "M_D_CPU0_SA_DQS_DN<5>")
	)
	(segment
		(start 294.425878 -307.961284)
		(end 293.976298 -307.961284)
		(width 0.18288)
		(layer "In6.Cu")
		(net "M_D_CPU0_SA_DQS_DN<5>")
	)
	(segment
		(start 298.806362 -305.691794)
		(end 298.515532 -305.400964)
		(width 0.18288)
		(layer "In6.Cu")
		(net "M_D_CPU0_SA_DQS_DN<5>")
	)
	(segment
		(start 281.89809 -311.910222)
		(end 280.575004 -311.36209)
		(width 0.18288)
		(layer "In6.Cu")
		(net "M_D_CPU0_SA_DQS_DN<5>")
	)
	(segment
		(start 340.151974 -274.762468)
		(end 340.14156 -274.756372)
		(width 0.088646)
		(layer "In6.Cu")
		(net "M_D_CPU0_SA_DQS_DN<5>")
	)
	(segment
		(start 344.258138 -274.963128)
		(end 343.926922 -274.771358)
		(width 0.088646)
		(layer "In6.Cu")
		(net "M_D_CPU0_SA_DQS_DN<5>")
	)
	(segment
		(start 295.184576 -308.241954)
		(end 294.706548 -308.241954)
		(width 0.18288)
		(layer "In6.Cu")
		(net "M_D_CPU0_SA_DQS_DN<5>")
	)
	(segment
		(start 337.230212 -275.8948)
		(end 337.230212 -275.904706)
		(width 0.088646)
		(layer "In6.Cu")
		(net "M_D_CPU0_SA_DQS_DN<5>")
	)
	(segment
		(start 296.215816 -307.451252)
		(end 295.705022 -307.962046)
		(width 0.18288)
		(layer "In6.Cu")
		(net "M_D_CPU0_SA_DQS_DN<5>")
	)
	(segment
		(start 334.880712 -276.708616)
		(end 334.880712 -276.72284)
		(width 0.088646)
		(layer "In6.Cu")
		(net "M_D_CPU0_SA_DQS_DN<5>")
	)
	(segment
		(start 307.73878 -299.43552)
		(end 306.907438 -300.266862)
		(width 0.18288)
		(layer "In6.Cu")
		(net "M_D_CPU0_SA_DQS_DN<5>")
	)
	(segment
		(start 339.767164 -274.756372)
		(end 339.75675 -274.762468)
		(width 0.088646)
		(layer "In6.Cu")
		(net "M_D_CPU0_SA_DQS_DN<5>")
	)
	(segment
		(start 283.718762 -313.341766)
		(end 283.427932 -313.050936)
		(width 0.18288)
		(layer "In6.Cu")
		(net "M_D_CPU0_SA_DQS_DN<5>")
	)
	(segment
		(start 291.50818 -309.9181)
		(end 291.065204 -309.9181)
		(width 0.18288)
		(layer "In6.Cu")
		(net "M_D_CPU0_SA_DQS_DN<5>")
	)
	(segment
		(start 337.887564 -274.756372)
		(end 337.878674 -274.761452)
		(width 0.088646)
		(layer "In6.Cu")
		(net "M_D_CPU0_SA_DQS_DN<5>")
	)
	(segment
		(start 276.555708 -311.382918)
		(end 274.074636 -311.382918)
		(width 0.18288)
		(layer "In6.Cu")
		(net "M_D_CPU0_SA_DQS_DN<5>")
	)
	(segment
		(start 344.466418 -275.405088)
		(end 344.457528 -275.400008)
		(width 0.088646)
		(layer "In6.Cu")
		(net "M_D_CPU0_SA_DQS_DN<5>")
	)
	(segment
		(start 280.004774 -311.641744)
		(end 279.618694 -311.641744)
		(width 0.18288)
		(layer "In6.Cu")
		(net "M_D_CPU0_SA_DQS_DN<5>")
	)
	(segment
		(start 269.465044 -311.78627)
		(end 269.109698 -311.78627)
		(width 0.18288)
		(layer "In6.Cu")
		(net "M_D_CPU0_SA_DQS_DN<5>")
	)
	(segment
		(start 316.307724 -294.896794)
		(end 314.185046 -297.019472)
		(width 0.18288)
		(layer "In6.Cu")
		(net "M_D_CPU0_SA_DQS_DN<5>")
	)
	(segment
		(start 277.974806 -310.76519)
		(end 277.173436 -310.76519)
		(width 0.18288)
		(layer "In6.Cu")
		(net "M_D_CPU0_SA_DQS_DN<5>")
	)
	(segment
		(start 330.774802 -280.106628)
		(end 330.298552 -280.303986)
		(width 0.18288)
		(layer "In6.Cu")
		(net "M_D_CPU0_SA_DQS_DN<5>")
	)
	(segment
		(start 309.66156 -298.0436)
		(end 308.26964 -299.43552)
		(width 0.18288)
		(layer "In6.Cu")
		(net "M_D_CPU0_SA_DQS_DN<5>")
	)
	(segment
		(start 304.450242 -302.595026)
		(end 303.166526 -303.878742)
		(width 0.18288)
		(layer "In6.Cu")
		(net "M_D_CPU0_SA_DQS_DN<5>")
	)
	(segment
		(start 335.457292 -276.392894)
		(end 335.44256 -276.384258)
		(width 0.088646)
		(layer "In6.Cu")
		(net "M_D_CPU0_SA_DQS_DN<5>")
	)
	(segment
		(start 333.337662 -277.912068)
		(end 332.229968 -279.019762)
		(width 0.088646)
		(layer "In6.Cu")
		(net "M_D_CPU0_SA_DQS_DN<5>")
	)
	(segment
		(start 333.337662 -277.50008)
		(end 333.337662 -277.912068)
		(width 0.088646)
		(layer "In6.Cu")
		(net "M_D_CPU0_SA_DQS_DN<5>")
	)
	(segment
		(start 296.92219 -306.149502)
		(end 296.215054 -306.856638)
		(width 0.18288)
		(layer "In6.Cu")
		(net "M_D_CPU0_SA_DQS_DN<5>")
	)
	(segment
		(start 294.706548 -308.241954)
		(end 294.425878 -307.961284)
		(width 0.18288)
		(layer "In6.Cu")
		(net "M_D_CPU0_SA_DQS_DN<5>")
	)
	(segment
		(start 296.215054 -306.856638)
		(end 296.215816 -307.451252)
		(width 0.18288)
		(layer "In6.Cu")
		(net "M_D_CPU0_SA_DQS_DN<5>")
	)
	(segment
		(start 304.836068 -302.595026)
		(end 304.450242 -302.595026)
		(width 0.18288)
		(layer "In6.Cu")
		(net "M_D_CPU0_SA_DQS_DN<5>")
	)
	(segment
		(start 338.272374 -274.762468)
		(end 338.26196 -274.756372)
		(width 0.088646)
		(layer "In6.Cu")
		(net "M_D_CPU0_SA_DQS_DN<5>")
	)
	(segment
		(start 306.907438 -300.266862)
		(end 306.646326 -300.266862)
		(width 0.18288)
		(layer "In6.Cu")
		(net "M_D_CPU0_SA_DQS_DN<5>")
	)
	(segment
		(start 308.26964 -299.43552)
		(end 307.73878 -299.43552)
		(width 0.18288)
		(layer "In6.Cu")
		(net "M_D_CPU0_SA_DQS_DN<5>")
	)
	(segment
		(start 284.111446 -313.341766)
		(end 283.718762 -313.341766)
		(width 0.18288)
		(layer "In6.Cu")
		(net "M_D_CPU0_SA_DQS_DN<5>")
	)
	(segment
		(start 292.838124 -308.588156)
		(end 291.50818 -309.9181)
		(width 0.18288)
		(layer "In6.Cu")
		(net "M_D_CPU0_SA_DQS_DN<5>")
	)
	(segment
		(start 306.020978 -300.89221)
		(end 306.020978 -301.410116)
		(width 0.18288)
		(layer "In6.Cu")
		(net "M_D_CPU0_SA_DQS_DN<5>")
	)
	(segment
		(start 299.284898 -305.691794)
		(end 298.806362 -305.691794)
		(width 0.18288)
		(layer "In6.Cu")
		(net "M_D_CPU0_SA_DQS_DN<5>")
	)
	(segment
		(start 300.538896 -305.41214)
		(end 299.564552 -305.41214)
		(width 0.18288)
		(layer "In6.Cu")
		(net "M_D_CPU0_SA_DQS_DN<5>")
	)
	(segment
		(start 344.278966 -274.983194)
		(end 344.258138 -274.963128)
		(width 0.088646)
		(layer "In6.Cu")
		(net "M_D_CPU0_SA_DQS_DN<5>")
	)
	(segment
		(start 278.592788 -311.383172)
		(end 277.974806 -310.76519)
		(width 0.18288)
		(layer "In6.Cu")
		(net "M_D_CPU0_SA_DQS_DN<5>")
	)
	(segment
		(start 283.038804 -313.050936)
		(end 281.89809 -311.910222)
		(width 0.18288)
		(layer "In6.Cu")
		(net "M_D_CPU0_SA_DQS_DN<5>")
	)
	(segment
		(start 343.926922 -274.771358)
		(end 343.904316 -274.758404)
		(width 0.088646)
		(layer "In6.Cu")
		(net "M_D_CPU0_SA_DQS_DN<5>")
	)
	(segment
		(start 343.904316 -274.758404)
		(end 343.902792 -274.757388)
		(width 0.088646)
		(layer "In6.Cu")
		(net "M_D_CPU0_SA_DQS_DN<5>")
	)
	(segment
		(start 272.469864 -312.047636)
		(end 269.72641 -312.047636)
		(width 0.18288)
		(layer "In6.Cu")
		(net "M_D_CPU0_SA_DQS_DN<5>")
	)
	(segment
		(start 279.618694 -311.641744)
		(end 279.360122 -311.383172)
		(width 0.18288)
		(layer "In6.Cu")
		(net "M_D_CPU0_SA_DQS_DN<5>")
	)
	(segment
		(start 274.074636 -311.382918)
		(end 272.469864 -312.047636)
		(width 0.18288)
		(layer "In6.Cu")
		(net "M_D_CPU0_SA_DQS_DN<5>")
	)
	(segment
		(start 310.912002 -298.0436)
		(end 309.66156 -298.0436)
		(width 0.18288)
		(layer "In6.Cu")
		(net "M_D_CPU0_SA_DQS_DN<5>")
	)
	(segment
		(start 331.436726 -280.106628)
		(end 330.774802 -280.106628)
		(width 0.18288)
		(layer "In6.Cu")
		(net "M_D_CPU0_SA_DQS_DN<5>")
	)
	(segment
		(start 337.700112 -275.08073)
		(end 337.700112 -275.099272)
		(width 0.088646)
		(layer "In6.Cu")
		(net "M_D_CPU0_SA_DQS_DN<5>")
	)
	(segment
		(start 312.427112 -298.447968)
		(end 311.31637 -298.447968)
		(width 0.18288)
		(layer "In6.Cu")
		(net "M_D_CPU0_SA_DQS_DN<5>")
	)
	(segment
		(start 337.417664 -275.570442)
		(end 337.408774 -275.575522)
		(width 0.088646)
		(layer "In6.Cu")
		(net "M_D_CPU0_SA_DQS_DN<5>")
	)
	(segment
		(start 314.185046 -297.019472)
		(end 313.855608 -297.019472)
		(width 0.18288)
		(layer "In6.Cu")
		(net "M_D_CPU0_SA_DQS_DN<5>")
	)
	(segment
		(start 298.135802 -305.400964)
		(end 297.387264 -306.149502)
		(width 0.18288)
		(layer "In6.Cu")
		(net "M_D_CPU0_SA_DQS_DN<5>")
	)
	(segment
		(start 332.229968 -279.699212)
		(end 331.882242 -280.046938)
		(width 0.088646)
		(layer "In6.Cu")
		(net "M_D_CPU0_SA_DQS_DN<5>")
	)
	(segment
		(start 283.427932 -313.050936)
		(end 283.038804 -313.050936)
		(width 0.18288)
		(layer "In6.Cu")
		(net "M_D_CPU0_SA_DQS_DN<5>")
	)
	(segment
		(start 313.855608 -297.019472)
		(end 312.427112 -298.447968)
		(width 0.18288)
		(layer "In6.Cu")
		(net "M_D_CPU0_SA_DQS_DN<5>")
	)
	(segment
		(start 298.515532 -305.400964)
		(end 298.135802 -305.400964)
		(width 0.18288)
		(layer "In6.Cu")
		(net "M_D_CPU0_SA_DQS_DN<5>")
	)
	(segment
		(start 269.109698 -311.78627)
		(end 268.829282 -312.066686)
		(width 0.18288)
		(layer "In6.Cu")
		(net "M_D_CPU0_SA_DQS_DN<5>")
	)
	(segment
		(start 297.387264 -306.149502)
		(end 296.92219 -306.149502)
		(width 0.18288)
		(layer "In6.Cu")
		(net "M_D_CPU0_SA_DQS_DN<5>")
	)
	(segment
		(start 306.020978 -301.410116)
		(end 304.836068 -302.595026)
		(width 0.18288)
		(layer "In6.Cu")
		(net "M_D_CPU0_SA_DQS_DN<5>")
	)
	(segment
		(start 345.593416 -275.08073)
		(end 344.870786 -275.387816)
		(width 0.088646)
		(layer "In6.Cu")
		(net "M_D_CPU0_SA_DQS_DN<5>")
	)
	(segment
		(start 342.975946 -274.765008)
		(end 342.961214 -274.756372)
		(width 0.088646)
		(layer "In6.Cu")
		(net "M_D_CPU0_SA_DQS_DN<5>")
	)
	(segment
		(start 295.705022 -307.962046)
		(end 295.464484 -307.962046)
		(width 0.18288)
		(layer "In6.Cu")
		(net "M_D_CPU0_SA_DQS_DN<5>")
	)
	(segment
		(start 279.360122 -311.383172)
		(end 278.592788 -311.383172)
		(width 0.18288)
		(layer "In6.Cu")
		(net "M_D_CPU0_SA_DQS_DN<5>")
	)
	(segment
		(start 331.460094 -280.106628)
		(end 331.436726 -280.106628)
		(width 0.088646)
		(layer "In6.Cu")
		(net "M_D_CPU0_SA_DQS_DN<5>")
	)
	(segment
		(start 303.166526 -303.878742)
		(end 302.072294 -303.878742)
		(width 0.18288)
		(layer "In6.Cu")
		(net "M_D_CPU0_SA_DQS_DN<5>")
	)
	(segment
		(start 330.298552 -280.303986)
		(end 316.307724 -294.294814)
		(width 0.18288)
		(layer "In6.Cu")
		(net "M_D_CPU0_SA_DQS_DN<5>")
	)
	(segment
		(start 295.464484 -307.962046)
		(end 295.184576 -308.241954)
		(width 0.18288)
		(layer "In6.Cu")
		(net "M_D_CPU0_SA_DQS_DN<5>")
	)
	(segment
		(start 344.278966 -275.08073)
		(end 344.278966 -274.983194)
		(width 0.088646)
		(layer "In6.Cu")
		(net "M_D_CPU0_SA_DQS_DN<5>")
	)
	(segment
		(start 306.646326 -300.266862)
		(end 306.020978 -300.89221)
		(width 0.18288)
		(layer "In6.Cu")
		(net "M_D_CPU0_SA_DQS_DN<5>")
	)
	(segment
		(start 285.181294 -313.062112)
		(end 284.3911 -313.062112)
		(width 0.18288)
		(layer "In6.Cu")
		(net "M_D_CPU0_SA_DQS_DN<5>")
	)
	(segment
		(start 316.307724 -294.294814)
		(end 316.307724 -294.896794)
		(width 0.18288)
		(layer "In6.Cu")
		(net "M_D_CPU0_SA_DQS_DN<5>")
	)
	(segment
		(start 280.284428 -311.36209)
		(end 280.004774 -311.641744)
		(width 0.18288)
		(layer "In6.Cu")
		(net "M_D_CPU0_SA_DQS_DN<5>")
	)
	(segment
		(start 289.859466 -311.123838)
		(end 285.181294 -313.062112)
		(width 0.18288)
		(layer "In6.Cu")
		(net "M_D_CPU0_SA_DQS_DN<5>")
	)
	(segment
		(start 280.575004 -311.36209)
		(end 280.284428 -311.36209)
		(width 0.18288)
		(layer "In6.Cu")
		(net "M_D_CPU0_SA_DQS_DN<5>")
	)
	(segment
		(start 331.882242 -280.046938)
		(end 331.519784 -280.046938)
		(width 0.088646)
		(layer "In6.Cu")
		(net "M_D_CPU0_SA_DQS_DN<5>")
	)
	(segment
		(start 302.072294 -303.878742)
		(end 300.538896 -305.41214)
		(width 0.18288)
		(layer "In6.Cu")
		(net "M_D_CPU0_SA_DQS_DN<5>")
	)
	(segment
		(start 293.976298 -307.961284)
		(end 293.349426 -308.588156)
		(width 0.18288)
		(layer "In6.Cu")
		(net "M_D_CPU0_SA_DQS_DN<5>")
	)
	(segment
		(start 277.173436 -310.76519)
		(end 276.555708 -311.382918)
		(width 0.18288)
		(layer "In6.Cu")
		(net "M_D_CPU0_SA_DQS_DN<5>")
	)
	(segment
		(start 291.065204 -309.9181)
		(end 289.859466 -311.123838)
		(width 0.18288)
		(layer "In6.Cu")
		(net "M_D_CPU0_SA_DQS_DN<5>")
	)
	(segment
		(start 331.519784 -280.046938)
		(end 331.460094 -280.106628)
		(width 0.088646)
		(layer "In6.Cu")
		(net "M_D_CPU0_SA_DQS_DN<5>")
	)
	(segment
		(start 284.3911 -313.062112)
		(end 284.111446 -313.341766)
		(width 0.18288)
		(layer "In6.Cu")
		(net "M_D_CPU0_SA_DQS_DN<5>")
	)
	(segment
		(start 332.229968 -279.019762)
		(end 332.229968 -279.699212)
		(width 0.088646)
		(layer "In6.Cu")
		(net "M_D_CPU0_SA_DQS_DN<5>")
	)
	(arc
		(start 337.408774 -275.575522)
		(mid 337.27786 -275.711882)
		(end 337.230212 -275.8948)
		(width 0.088646)
		(layer "In6.Cu")
		(net "M_D_CPU0_SA_DQS_DN<5>")
	)
	(arc
		(start 342.586818 -274.756372)
		(mid 342.312619 -274.832207)
		(end 342.036146 -274.765008)
		(width 0.088646)
		(layer "In6.Cu")
		(net "M_D_CPU0_SA_DQS_DN<5>")
	)
	(arc
		(start 337.230212 -275.904706)
		(mid 337.152101 -276.181655)
		(end 336.947764 -276.384258)
		(width 0.088646)
		(layer "In6.Cu")
		(net "M_D_CPU0_SA_DQS_DN<5>")
	)
	(arc
		(start 338.827618 -274.756372)
		(mid 338.550805 -274.832242)
		(end 338.272374 -274.762468)
		(width 0.088646)
		(layer "In6.Cu")
		(net "M_D_CPU0_SA_DQS_DN<5>")
	)
	(arc
		(start 344.457528 -275.400008)
		(mid 344.326614 -275.263648)
		(end 344.278966 -275.08073)
		(width 0.088646)
		(layer "In6.Cu")
		(net "M_D_CPU0_SA_DQS_DN<5>")
	)
	(arc
		(start 333.65821 -277.198328)
		(mid 333.61728 -277.225361)
		(end 333.580232 -277.25751)
		(width 0.088646)
		(layer "In6.Cu")
		(net "M_D_CPU0_SA_DQS_DN<5>")
	)
	(arc
		(start 335.059274 -276.389338)
		(mid 334.92836 -276.525698)
		(end 334.880712 -276.708616)
		(width 0.088646)
		(layer "In6.Cu")
		(net "M_D_CPU0_SA_DQS_DN<5>")
	)
	(arc
		(start 338.26196 -274.756372)
		(mid 338.074762 -274.706229)
		(end 337.887564 -274.756372)
		(width 0.088646)
		(layer "In6.Cu")
		(net "M_D_CPU0_SA_DQS_DN<5>")
	)
	(arc
		(start 341.647018 -274.756372)
		(mid 341.372819 -274.832207)
		(end 341.096346 -274.765008)
		(width 0.088646)
		(layer "In6.Cu")
		(net "M_D_CPU0_SA_DQS_DN<5>")
	)
	(arc
		(start 342.021414 -274.756372)
		(mid 341.834216 -274.706229)
		(end 341.647018 -274.756372)
		(width 0.088646)
		(layer "In6.Cu")
		(net "M_D_CPU0_SA_DQS_DN<5>")
	)
	(arc
		(start 334.880712 -276.72284)
		(mid 334.801493 -276.997525)
		(end 334.59801 -277.198328)
		(width 0.088646)
		(layer "In6.Cu")
		(net "M_D_CPU0_SA_DQS_DN<5>")
	)
	(arc
		(start 340.707218 -274.756372)
		(mid 340.430405 -274.832242)
		(end 340.151974 -274.762468)
		(width 0.088646)
		(layer "In6.Cu")
		(net "M_D_CPU0_SA_DQS_DN<5>")
	)
	(arc
		(start 343.901014 -274.756372)
		(mid 343.713816 -274.706229)
		(end 343.526618 -274.756372)
		(width 0.088646)
		(layer "In6.Cu")
		(net "M_D_CPU0_SA_DQS_DN<5>")
	)
	(arc
		(start 336.007964 -276.384258)
		(mid 335.733765 -276.460093)
		(end 335.457292 -276.392894)
		(width 0.088646)
		(layer "In6.Cu")
		(net "M_D_CPU0_SA_DQS_DN<5>")
	)
	(arc
		(start 336.947764 -276.384258)
		(mid 336.665062 -276.460034)
		(end 336.38236 -276.384258)
		(width 0.088646)
		(layer "In6.Cu")
		(net "M_D_CPU0_SA_DQS_DN<5>")
	)
	(arc
		(start 334.583278 -277.206964)
		(mid 334.306837 -277.27413)
		(end 334.032606 -277.198328)
		(width 0.088646)
		(layer "In6.Cu")
		(net "M_D_CPU0_SA_DQS_DN<5>")
	)
	(arc
		(start 336.38236 -276.384258)
		(mid 336.195162 -276.334115)
		(end 336.007964 -276.384258)
		(width 0.088646)
		(layer "In6.Cu")
		(net "M_D_CPU0_SA_DQS_DN<5>")
	)
	(arc
		(start 342.961214 -274.756372)
		(mid 342.774016 -274.706229)
		(end 342.586818 -274.756372)
		(width 0.088646)
		(layer "In6.Cu")
		(net "M_D_CPU0_SA_DQS_DN<5>")
	)
	(arc
		(start 343.526618 -274.756372)
		(mid 343.252419 -274.832207)
		(end 342.975946 -274.765008)
		(width 0.088646)
		(layer "In6.Cu")
		(net "M_D_CPU0_SA_DQS_DN<5>")
	)
	(arc
		(start 340.14156 -274.756372)
		(mid 339.954362 -274.706229)
		(end 339.767164 -274.756372)
		(width 0.088646)
		(layer "In6.Cu")
		(net "M_D_CPU0_SA_DQS_DN<5>")
	)
	(arc
		(start 337.700112 -275.099272)
		(mid 337.61995 -275.371461)
		(end 337.417664 -275.570442)
		(width 0.088646)
		(layer "In6.Cu")
		(net "M_D_CPU0_SA_DQS_DN<5>")
	)
	(arc
		(start 339.202014 -274.756372)
		(mid 339.014816 -274.706229)
		(end 338.827618 -274.756372)
		(width 0.088646)
		(layer "In6.Cu")
		(net "M_D_CPU0_SA_DQS_DN<5>")
	)
	(arc
		(start 339.75675 -274.762468)
		(mid 339.478572 -274.832191)
		(end 339.202014 -274.756372)
		(width 0.088646)
		(layer "In6.Cu")
		(net "M_D_CPU0_SA_DQS_DN<5>")
	)
	(arc
		(start 337.878674 -274.761452)
		(mid 337.74776 -274.897812)
		(end 337.700112 -275.08073)
		(width 0.088646)
		(layer "In6.Cu")
		(net "M_D_CPU0_SA_DQS_DN<5>")
	)
	(arc
		(start 341.081614 -274.756372)
		(mid 340.894416 -274.706229)
		(end 340.707218 -274.756372)
		(width 0.088646)
		(layer "In6.Cu")
		(net "M_D_CPU0_SA_DQS_DN<5>")
	)
	(arc
		(start 334.032606 -277.198328)
		(mid 333.845408 -277.148185)
		(end 333.65821 -277.198328)
		(width 0.088646)
		(layer "In6.Cu")
		(net "M_D_CPU0_SA_DQS_DN<5>")
	)
	(arc
		(start 344.840814 -275.405088)
		(mid 344.653616 -275.455231)
		(end 344.466418 -275.405088)
		(width 0.088646)
		(layer "In6.Cu")
		(net "M_D_CPU0_SA_DQS_DN<5>")
	)
	(arc
		(start 335.44256 -276.384258)
		(mid 335.255362 -276.334115)
		(end 335.068164 -276.384258)
		(width 0.088646)
		(layer "In6.Cu")
		(net "M_D_CPU0_SA_DQS_DN<5>")
	)
	(segment
		(start 258.852162 -275.080984)
		(end 258.580128 -275.353018)
		(width 0.20066)
		(layer "F.Cu")
		(net "M_D_CPU0_SA_DQS_DN<4>")
	)
	(segment
		(start 346.063316 -262.87222)
		(end 346.063062 -262.872474)
		(width 0.20066)
		(layer "F.Cu")
		(net "M_D_CPU0_SA_DQS_DN<4>")
	)
	(segment
		(start 262.816594 -274.927822)
		(end 262.40994 -274.927822)
		(width 0.20066)
		(layer "F.Cu")
		(net "M_D_CPU0_SA_DQS_DN<4>")
	)
	(segment
		(start 259.067808 -275.091652)
		(end 259.05714 -275.080984)
		(width 0.101854)
		(layer "F.Cu")
		(net "M_D_CPU0_SA_DQS_DN<4>")
	)
	(segment
		(start 256.890266 -274.927822)
		(end 256.629154 -274.66671)
		(width 0.20066)
		(layer "F.Cu")
		(net "M_D_CPU0_SA_DQS_DN<4>")
	)
	(segment
		(start 258.580128 -275.353018)
		(end 258.040124 -275.353018)
		(width 0.20066)
		(layer "F.Cu")
		(net "M_D_CPU0_SA_DQS_DN<4>")
	)
	(segment
		(start 258.040124 -275.353018)
		(end 257.404108 -274.927822)
		(width 0.20066)
		(layer "F.Cu")
		(net "M_D_CPU0_SA_DQS_DN<4>")
	)
	(segment
		(start 346.063316 -262.336534)
		(end 346.063316 -262.87222)
		(width 0.20066)
		(layer "F.Cu")
		(net "M_D_CPU0_SA_DQS_DN<4>")
	)
	(segment
		(start 259.05714 -275.080984)
		(end 259.056378 -275.080984)
		(width 0.101854)
		(layer "F.Cu")
		(net "M_D_CPU0_SA_DQS_DN<4>")
	)
	(segment
		(start 261.381494 -275.091652)
		(end 259.067808 -275.091652)
		(width 0.1016)
		(layer "F.Cu")
		(net "M_D_CPU0_SA_DQS_DN<4>")
	)
	(segment
		(start 261.984744 -275.353018)
		(end 261.798054 -275.353018)
		(width 0.20066)
		(layer "F.Cu")
		(net "M_D_CPU0_SA_DQS_DN<4>")
	)
	(segment
		(start 261.798054 -275.353018)
		(end 261.536688 -275.091652)
		(width 0.20066)
		(layer "F.Cu")
		(net "M_D_CPU0_SA_DQS_DN<4>")
	)
	(segment
		(start 261.536688 -275.091652)
		(end 261.381494 -275.091652)
		(width 0.20066)
		(layer "F.Cu")
		(net "M_D_CPU0_SA_DQS_DN<4>")
	)
	(segment
		(start 256.629154 -274.66671)
		(end 256.080514 -274.66671)
		(width 0.20066)
		(layer "F.Cu")
		(net "M_D_CPU0_SA_DQS_DN<4>")
	)
	(segment
		(start 263.077706 -274.66671)
		(end 262.816594 -274.927822)
		(width 0.20066)
		(layer "F.Cu")
		(net "M_D_CPU0_SA_DQS_DN<4>")
	)
	(segment
		(start 264.729214 -274.66671)
		(end 263.624314 -274.66671)
		(width 0.20066)
		(layer "F.Cu")
		(net "M_D_CPU0_SA_DQS_DN<4>")
	)
	(segment
		(start 259.056378 -275.080984)
		(end 258.852162 -275.080984)
		(width 0.20066)
		(layer "F.Cu")
		(net "M_D_CPU0_SA_DQS_DN<4>")
	)
	(segment
		(start 263.624314 -274.66671)
		(end 263.077706 -274.66671)
		(width 0.20066)
		(layer "F.Cu")
		(net "M_D_CPU0_SA_DQS_DN<4>")
	)
	(segment
		(start 257.404108 -274.927822)
		(end 256.890266 -274.927822)
		(width 0.20066)
		(layer "F.Cu")
		(net "M_D_CPU0_SA_DQS_DN<4>")
	)
	(segment
		(start 262.40994 -274.927822)
		(end 261.984744 -275.353018)
		(width 0.20066)
		(layer "F.Cu")
		(net "M_D_CPU0_SA_DQS_DN<4>")
	)
	(segment
		(start 299.21073 -272.540984)
		(end 298.813982 -272.540984)
		(width 0.18288)
		(layer "In11.Cu")
		(net "M_D_CPU0_SA_DQS_DN<4>")
	)
	(segment
		(start 290.342574 -273.556984)
		(end 289.793934 -273.556984)
		(width 0.18288)
		(layer "In11.Cu")
		(net "M_D_CPU0_SA_DQS_DN<4>")
	)
	(segment
		(start 306.414424 -271.962626)
		(end 305.865784 -271.962626)
		(width 0.18288)
		(layer "In11.Cu")
		(net "M_D_CPU0_SA_DQS_DN<4>")
	)
	(segment
		(start 278.799544 -273.656806)
		(end 278.108664 -274.347686)
		(width 0.18288)
		(layer "In11.Cu")
		(net "M_D_CPU0_SA_DQS_DN<4>")
	)
	(segment
		(start 346.063062 -262.872474)
		(end 346.031312 -262.988298)
		(width 0.088646)
		(layer "In11.Cu")
		(net "M_D_CPU0_SA_DQS_DN<4>")
	)
	(segment
		(start 341.176864 -263.196832)
		(end 341.162132 -263.188196)
		(width 0.088646)
		(layer "In11.Cu")
		(net "M_D_CPU0_SA_DQS_DN<4>")
	)
	(segment
		(start 278.108664 -274.347686)
		(end 277.444708 -274.347686)
		(width 0.18288)
		(layer "In11.Cu")
		(net "M_D_CPU0_SA_DQS_DN<4>")
	)
	(segment
		(start 331.3557 -263.643364)
		(end 331.03693 -263.643364)
		(width 0.088646)
		(layer "In11.Cu")
		(net "M_D_CPU0_SA_DQS_DN<4>")
	)
	(segment
		(start 288.996374 -273.556984)
		(end 288.185606 -273.556984)
		(width 0.18288)
		(layer "In11.Cu")
		(net "M_D_CPU0_SA_DQS_DN<4>")
	)
	(segment
		(start 297.697398 -272.818606)
		(end 296.882312 -273.633692)
		(width 0.18288)
		(layer "In11.Cu")
		(net "M_D_CPU0_SA_DQS_DN<4>")
	)
	(segment
		(start 268.621002 -275.092414)
		(end 268.369542 -275.343874)
		(width 0.18288)
		(layer "In11.Cu")
		(net "M_D_CPU0_SA_DQS_DN<4>")
	)
	(segment
		(start 292.479476 -274.347686)
		(end 291.688774 -273.556984)
		(width 0.18288)
		(layer "In11.Cu")
		(net "M_D_CPU0_SA_DQS_DN<4>")
	)
	(segment
		(start 301.723552 -272.793714)
		(end 301.174912 -272.793714)
		(width 0.18288)
		(layer "In11.Cu")
		(net "M_D_CPU0_SA_DQS_DN<4>")
	)
	(segment
		(start 300.501812 -272.669254)
		(end 300.377352 -272.793714)
		(width 0.18288)
		(layer "In11.Cu")
		(net "M_D_CPU0_SA_DQS_DN<4>")
	)
	(segment
		(start 312.323226 -271.612106)
		(end 312.198766 -271.736566)
		(width 0.18288)
		(layer "In11.Cu")
		(net "M_D_CPU0_SA_DQS_DN<4>")
	)
	(segment
		(start 288.185606 -273.556984)
		(end 287.430972 -272.80235)
		(width 0.18288)
		(layer "In11.Cu")
		(net "M_D_CPU0_SA_DQS_DN<4>")
	)
	(segment
		(start 299.46346 -272.793714)
		(end 299.21073 -272.540984)
		(width 0.18288)
		(layer "In11.Cu")
		(net "M_D_CPU0_SA_DQS_DN<4>")
	)
	(segment
		(start 295.376346 -273.633692)
		(end 295.135046 -273.392392)
		(width 0.18288)
		(layer "In11.Cu")
		(net "M_D_CPU0_SA_DQS_DN<4>")
	)
	(segment
		(start 307.087524 -272.087086)
		(end 306.538884 -272.087086)
		(width 0.18288)
		(layer "In11.Cu")
		(net "M_D_CPU0_SA_DQS_DN<4>")
	)
	(segment
		(start 265.752326 -274.936204)
		(end 264.998708 -274.936204)
		(width 0.18288)
		(layer "In11.Cu")
		(net "M_D_CPU0_SA_DQS_DN<4>")
	)
	(segment
		(start 276.953218 -273.856196)
		(end 273.572478 -273.856196)
		(width 0.18288)
		(layer "In11.Cu")
		(net "M_D_CPU0_SA_DQS_DN<4>")
	)
	(segment
		(start 301.050452 -272.669254)
		(end 300.501812 -272.669254)
		(width 0.18288)
		(layer "In11.Cu")
		(net "M_D_CPU0_SA_DQS_DN<4>")
	)
	(segment
		(start 294.71239 -273.392392)
		(end 294.43553 -273.669252)
		(width 0.18288)
		(layer "In11.Cu")
		(net "M_D_CPU0_SA_DQS_DN<4>")
	)
	(segment
		(start 287.430972 -272.80235)
		(end 286.818832 -272.80235)
		(width 0.18288)
		(layer "In11.Cu")
		(net "M_D_CPU0_SA_DQS_DN<4>")
	)
	(segment
		(start 283.717238 -272.540984)
		(end 283.473144 -272.785078)
		(width 0.18288)
		(layer "In11.Cu")
		(net "M_D_CPU0_SA_DQS_DN<4>")
	)
	(segment
		(start 344.936318 -263.196832)
		(end 344.925904 -263.190736)
		(width 0.088646)
		(layer "In11.Cu")
		(net "M_D_CPU0_SA_DQS_DN<4>")
	)
	(segment
		(start 339.297264 -263.196832)
		(end 339.28685 -263.190736)
		(width 0.088646)
		(layer "In11.Cu")
		(net "M_D_CPU0_SA_DQS_DN<4>")
	)
	(segment
		(start 331.03693 -263.643364)
		(end 330.97724 -263.583674)
		(width 0.088646)
		(layer "In11.Cu")
		(net "M_D_CPU0_SA_DQS_DN<4>")
	)
	(segment
		(start 271.784064 -274.347686)
		(end 270.77035 -275.3614)
		(width 0.18288)
		(layer "In11.Cu")
		(net "M_D_CPU0_SA_DQS_DN<4>")
	)
	(segment
		(start 345.837764 -263.05129)
		(end 345.564206 -263.05129)
		(width 0.088646)
		(layer "In11.Cu")
		(net "M_D_CPU0_SA_DQS_DN<4>")
	)
	(segment
		(start 305.192684 -272.087086)
		(end 305.068224 -271.962626)
		(width 0.18288)
		(layer "In11.Cu")
		(net "M_D_CPU0_SA_DQS_DN<4>")
	)
	(segment
		(start 305.741324 -272.087086)
		(end 305.192684 -272.087086)
		(width 0.18288)
		(layer "In11.Cu")
		(net "M_D_CPU0_SA_DQS_DN<4>")
	)
	(segment
		(start 312.871866 -271.612106)
		(end 312.323226 -271.612106)
		(width 0.18288)
		(layer "In11.Cu")
		(net "M_D_CPU0_SA_DQS_DN<4>")
	)
	(segment
		(start 282.877006 -272.785078)
		(end 282.013914 -273.64817)
		(width 0.18288)
		(layer "In11.Cu")
		(net "M_D_CPU0_SA_DQS_DN<4>")
	)
	(segment
		(start 286.818832 -272.80235)
		(end 286.694372 -272.67789)
		(width 0.18288)
		(layer "In11.Cu")
		(net "M_D_CPU0_SA_DQS_DN<4>")
	)
	(segment
		(start 289.669474 -273.432524)
		(end 289.120834 -273.432524)
		(width 0.18288)
		(layer "In11.Cu")
		(net "M_D_CPU0_SA_DQS_DN<4>")
	)
	(segment
		(start 330.97724 -263.583674)
		(end 323.363844 -263.583674)
		(width 0.18288)
		(layer "In11.Cu")
		(net "M_D_CPU0_SA_DQS_DN<4>")
	)
	(segment
		(start 309.139336 -272.44167)
		(end 308.590696 -272.44167)
		(width 0.18288)
		(layer "In11.Cu")
		(net "M_D_CPU0_SA_DQS_DN<4>")
	)
	(segment
		(start 346.031312 -262.988298)
		(end 345.99245 -263.010396)
		(width 0.088646)
		(layer "In11.Cu")
		(net "M_D_CPU0_SA_DQS_DN<4>")
	)
	(segment
		(start 286.694372 -272.67789)
		(end 286.145732 -272.67789)
		(width 0.18288)
		(layer "In11.Cu")
		(net "M_D_CPU0_SA_DQS_DN<4>")
	)
	(segment
		(start 312.996326 -271.736566)
		(end 312.871866 -271.612106)
		(width 0.18288)
		(layer "In11.Cu")
		(net "M_D_CPU0_SA_DQS_DN<4>")
	)
	(segment
		(start 303.77638 -272.087086)
		(end 303.069752 -272.793714)
		(width 0.18288)
		(layer "In11.Cu")
		(net "M_D_CPU0_SA_DQS_DN<4>")
	)
	(segment
		(start 323.363844 -263.583674)
		(end 315.210952 -271.736566)
		(width 0.18288)
		(layer "In11.Cu")
		(net "M_D_CPU0_SA_DQS_DN<4>")
	)
	(segment
		(start 273.572478 -273.856196)
		(end 273.080988 -274.347686)
		(width 0.18288)
		(layer "In11.Cu")
		(net "M_D_CPU0_SA_DQS_DN<4>")
	)
	(segment
		(start 280.015442 -273.392392)
		(end 279.608534 -273.392392)
		(width 0.18288)
		(layer "In11.Cu")
		(net "M_D_CPU0_SA_DQS_DN<4>")
	)
	(segment
		(start 296.882312 -273.633692)
		(end 295.376346 -273.633692)
		(width 0.18288)
		(layer "In11.Cu")
		(net "M_D_CPU0_SA_DQS_DN<4>")
	)
	(segment
		(start 298.53636 -272.818606)
		(end 297.697398 -272.818606)
		(width 0.18288)
		(layer "In11.Cu")
		(net "M_D_CPU0_SA_DQS_DN<4>")
	)
	(segment
		(start 345.564206 -263.05129)
		(end 345.310968 -263.197086)
		(width 0.088646)
		(layer "In11.Cu")
		(net "M_D_CPU0_SA_DQS_DN<4>")
	)
	(segment
		(start 284.121606 -272.540984)
		(end 283.717238 -272.540984)
		(width 0.18288)
		(layer "In11.Cu")
		(net "M_D_CPU0_SA_DQS_DN<4>")
	)
	(segment
		(start 302.521112 -272.793714)
		(end 302.396652 -272.669254)
		(width 0.18288)
		(layer "In11.Cu")
		(net "M_D_CPU0_SA_DQS_DN<4>")
	)
	(segment
		(start 290.467034 -273.432524)
		(end 290.342574 -273.556984)
		(width 0.18288)
		(layer "In11.Cu")
		(net "M_D_CPU0_SA_DQS_DN<4>")
	)
	(segment
		(start 293.011098 -274.347686)
		(end 292.479476 -274.347686)
		(width 0.18288)
		(layer "In11.Cu")
		(net "M_D_CPU0_SA_DQS_DN<4>")
	)
	(segment
		(start 264.998708 -274.936204)
		(end 264.729214 -274.66671)
		(width 0.18288)
		(layer "In11.Cu")
		(net "M_D_CPU0_SA_DQS_DN<4>")
	)
	(segment
		(start 267.107924 -274.576286)
		(end 266.112244 -274.576286)
		(width 0.18288)
		(layer "In11.Cu")
		(net "M_D_CPU0_SA_DQS_DN<4>")
	)
	(segment
		(start 280.27122 -273.64817)
		(end 280.015442 -273.392392)
		(width 0.18288)
		(layer "In11.Cu")
		(net "M_D_CPU0_SA_DQS_DN<4>")
	)
	(segment
		(start 289.793934 -273.556984)
		(end 289.669474 -273.432524)
		(width 0.18288)
		(layer "In11.Cu")
		(net "M_D_CPU0_SA_DQS_DN<4>")
	)
	(segment
		(start 311.403746 -271.736566)
		(end 310.574182 -272.56613)
		(width 0.18288)
		(layer "In11.Cu")
		(net "M_D_CPU0_SA_DQS_DN<4>")
	)
	(segment
		(start 331.751432 -263.247632)
		(end 331.3557 -263.643364)
		(width 0.088646)
		(layer "In11.Cu")
		(net "M_D_CPU0_SA_DQS_DN<4>")
	)
	(segment
		(start 308.466236 -272.56613)
		(end 307.566568 -272.56613)
		(width 0.18288)
		(layer "In11.Cu")
		(net "M_D_CPU0_SA_DQS_DN<4>")
	)
	(segment
		(start 291.140134 -273.556984)
		(end 291.015674 -273.432524)
		(width 0.18288)
		(layer "In11.Cu")
		(net "M_D_CPU0_SA_DQS_DN<4>")
	)
	(segment
		(start 305.068224 -271.962626)
		(end 304.519584 -271.962626)
		(width 0.18288)
		(layer "In11.Cu")
		(net "M_D_CPU0_SA_DQS_DN<4>")
	)
	(segment
		(start 310.574182 -272.56613)
		(end 309.263796 -272.56613)
		(width 0.18288)
		(layer "In11.Cu")
		(net "M_D_CPU0_SA_DQS_DN<4>")
	)
	(segment
		(start 269.28953 -275.3614)
		(end 269.020544 -275.092414)
		(width 0.18288)
		(layer "In11.Cu")
		(net "M_D_CPU0_SA_DQS_DN<4>")
	)
	(segment
		(start 331.966062 -263.247632)
		(end 331.751432 -263.247632)
		(width 0.088646)
		(layer "In11.Cu")
		(net "M_D_CPU0_SA_DQS_DN<4>")
	)
	(segment
		(start 269.020544 -275.092414)
		(end 268.621002 -275.092414)
		(width 0.18288)
		(layer "In11.Cu")
		(net "M_D_CPU0_SA_DQS_DN<4>")
	)
	(segment
		(start 307.566568 -272.56613)
		(end 307.087524 -272.087086)
		(width 0.18288)
		(layer "In11.Cu")
		(net "M_D_CPU0_SA_DQS_DN<4>")
	)
	(segment
		(start 279.34412 -273.656806)
		(end 278.799544 -273.656806)
		(width 0.18288)
		(layer "In11.Cu")
		(net "M_D_CPU0_SA_DQS_DN<4>")
	)
	(segment
		(start 283.473144 -272.785078)
		(end 282.877006 -272.785078)
		(width 0.18288)
		(layer "In11.Cu")
		(net "M_D_CPU0_SA_DQS_DN<4>")
	)
	(segment
		(start 304.519584 -271.962626)
		(end 304.395124 -272.087086)
		(width 0.18288)
		(layer "In11.Cu")
		(net "M_D_CPU0_SA_DQS_DN<4>")
	)
	(segment
		(start 282.013914 -273.64817)
		(end 280.27122 -273.64817)
		(width 0.18288)
		(layer "In11.Cu")
		(net "M_D_CPU0_SA_DQS_DN<4>")
	)
	(segment
		(start 291.015674 -273.432524)
		(end 290.467034 -273.432524)
		(width 0.18288)
		(layer "In11.Cu")
		(net "M_D_CPU0_SA_DQS_DN<4>")
	)
	(segment
		(start 303.069752 -272.793714)
		(end 302.521112 -272.793714)
		(width 0.18288)
		(layer "In11.Cu")
		(net "M_D_CPU0_SA_DQS_DN<4>")
	)
	(segment
		(start 304.395124 -272.087086)
		(end 303.77638 -272.087086)
		(width 0.18288)
		(layer "In11.Cu")
		(net "M_D_CPU0_SA_DQS_DN<4>")
	)
	(segment
		(start 302.396652 -272.669254)
		(end 301.848012 -272.669254)
		(width 0.18288)
		(layer "In11.Cu")
		(net "M_D_CPU0_SA_DQS_DN<4>")
	)
	(segment
		(start 305.865784 -271.962626)
		(end 305.741324 -272.087086)
		(width 0.18288)
		(layer "In11.Cu")
		(net "M_D_CPU0_SA_DQS_DN<4>")
	)
	(segment
		(start 342.116664 -263.196832)
		(end 342.101932 -263.188196)
		(width 0.088646)
		(layer "In11.Cu")
		(net "M_D_CPU0_SA_DQS_DN<4>")
	)
	(segment
		(start 293.689532 -273.669252)
		(end 293.011098 -274.347686)
		(width 0.18288)
		(layer "In11.Cu")
		(net "M_D_CPU0_SA_DQS_DN<4>")
	)
	(segment
		(start 295.135046 -273.392392)
		(end 294.71239 -273.392392)
		(width 0.18288)
		(layer "In11.Cu")
		(net "M_D_CPU0_SA_DQS_DN<4>")
	)
	(segment
		(start 294.43553 -273.669252)
		(end 293.689532 -273.669252)
		(width 0.18288)
		(layer "In11.Cu")
		(net "M_D_CPU0_SA_DQS_DN<4>")
	)
	(segment
		(start 345.310968 -263.197086)
		(end 345.310714 -263.196832)
		(width 0.088646)
		(layer "In11.Cu")
		(net "M_D_CPU0_SA_DQS_DN<4>")
	)
	(segment
		(start 306.538884 -272.087086)
		(end 306.414424 -271.962626)
		(width 0.18288)
		(layer "In11.Cu")
		(net "M_D_CPU0_SA_DQS_DN<4>")
	)
	(segment
		(start 266.112244 -274.576286)
		(end 265.752326 -274.936204)
		(width 0.18288)
		(layer "In11.Cu")
		(net "M_D_CPU0_SA_DQS_DN<4>")
	)
	(segment
		(start 301.848012 -272.669254)
		(end 301.723552 -272.793714)
		(width 0.18288)
		(layer "In11.Cu")
		(net "M_D_CPU0_SA_DQS_DN<4>")
	)
	(segment
		(start 337.802474 -263.190736)
		(end 337.79206 -263.196832)
		(width 0.088646)
		(layer "In11.Cu")
		(net "M_D_CPU0_SA_DQS_DN<4>")
	)
	(segment
		(start 312.198766 -271.736566)
		(end 311.403746 -271.736566)
		(width 0.18288)
		(layer "In11.Cu")
		(net "M_D_CPU0_SA_DQS_DN<4>")
	)
	(segment
		(start 286.145732 -272.67789)
		(end 286.021272 -272.80235)
		(width 0.18288)
		(layer "In11.Cu")
		(net "M_D_CPU0_SA_DQS_DN<4>")
	)
	(segment
		(start 286.021272 -272.80235)
		(end 284.382972 -272.80235)
		(width 0.18288)
		(layer "In11.Cu")
		(net "M_D_CPU0_SA_DQS_DN<4>")
	)
	(segment
		(start 309.263796 -272.56613)
		(end 309.139336 -272.44167)
		(width 0.18288)
		(layer "In11.Cu")
		(net "M_D_CPU0_SA_DQS_DN<4>")
	)
	(segment
		(start 315.210952 -271.736566)
		(end 312.996326 -271.736566)
		(width 0.18288)
		(layer "In11.Cu")
		(net "M_D_CPU0_SA_DQS_DN<4>")
	)
	(segment
		(start 298.813982 -272.540984)
		(end 298.53636 -272.818606)
		(width 0.18288)
		(layer "In11.Cu")
		(net "M_D_CPU0_SA_DQS_DN<4>")
	)
	(segment
		(start 291.688774 -273.556984)
		(end 291.140134 -273.556984)
		(width 0.18288)
		(layer "In11.Cu")
		(net "M_D_CPU0_SA_DQS_DN<4>")
	)
	(segment
		(start 270.77035 -275.3614)
		(end 269.28953 -275.3614)
		(width 0.18288)
		(layer "In11.Cu")
		(net "M_D_CPU0_SA_DQS_DN<4>")
	)
	(segment
		(start 267.875512 -275.343874)
		(end 267.107924 -274.576286)
		(width 0.18288)
		(layer "In11.Cu")
		(net "M_D_CPU0_SA_DQS_DN<4>")
	)
	(segment
		(start 273.080988 -274.347686)
		(end 271.784064 -274.347686)
		(width 0.18288)
		(layer "In11.Cu")
		(net "M_D_CPU0_SA_DQS_DN<4>")
	)
	(segment
		(start 268.369542 -275.343874)
		(end 267.875512 -275.343874)
		(width 0.18288)
		(layer "In11.Cu")
		(net "M_D_CPU0_SA_DQS_DN<4>")
	)
	(segment
		(start 343.996264 -263.196832)
		(end 343.981532 -263.188196)
		(width 0.088646)
		(layer "In11.Cu")
		(net "M_D_CPU0_SA_DQS_DN<4>")
	)
	(segment
		(start 340.237064 -263.196832)
		(end 340.222332 -263.188196)
		(width 0.088646)
		(layer "In11.Cu")
		(net "M_D_CPU0_SA_DQS_DN<4>")
	)
	(segment
		(start 284.382972 -272.80235)
		(end 284.121606 -272.540984)
		(width 0.18288)
		(layer "In11.Cu")
		(net "M_D_CPU0_SA_DQS_DN<4>")
	)
	(segment
		(start 300.377352 -272.793714)
		(end 299.46346 -272.793714)
		(width 0.18288)
		(layer "In11.Cu")
		(net "M_D_CPU0_SA_DQS_DN<4>")
	)
	(segment
		(start 308.590696 -272.44167)
		(end 308.466236 -272.56613)
		(width 0.18288)
		(layer "In11.Cu")
		(net "M_D_CPU0_SA_DQS_DN<4>")
	)
	(segment
		(start 301.174912 -272.793714)
		(end 301.050452 -272.669254)
		(width 0.18288)
		(layer "In11.Cu")
		(net "M_D_CPU0_SA_DQS_DN<4>")
	)
	(segment
		(start 289.120834 -273.432524)
		(end 288.996374 -273.556984)
		(width 0.18288)
		(layer "In11.Cu")
		(net "M_D_CPU0_SA_DQS_DN<4>")
	)
	(segment
		(start 279.608534 -273.392392)
		(end 279.34412 -273.656806)
		(width 0.18288)
		(layer "In11.Cu")
		(net "M_D_CPU0_SA_DQS_DN<4>")
	)
	(segment
		(start 277.444708 -274.347686)
		(end 276.953218 -273.856196)
		(width 0.18288)
		(layer "In11.Cu")
		(net "M_D_CPU0_SA_DQS_DN<4>")
	)
	(arc
		(start 335.538064 -263.196832)
		(mid 335.255362 -263.12109)
		(end 334.97266 -263.196832)
		(width 0.088646)
		(layer "In11.Cu")
		(net "M_D_CPU0_SA_DQS_DN<4>")
	)
	(arc
		(start 336.85226 -263.196832)
		(mid 336.665062 -263.246975)
		(end 336.477864 -263.196832)
		(width 0.088646)
		(layer "In11.Cu")
		(net "M_D_CPU0_SA_DQS_DN<4>")
	)
	(arc
		(start 339.67166 -263.196832)
		(mid 339.484462 -263.246975)
		(end 339.297264 -263.196832)
		(width 0.088646)
		(layer "In11.Cu")
		(net "M_D_CPU0_SA_DQS_DN<4>")
	)
	(arc
		(start 338.732114 -263.196832)
		(mid 338.544916 -263.246975)
		(end 338.357718 -263.196832)
		(width 0.088646)
		(layer "In11.Cu")
		(net "M_D_CPU0_SA_DQS_DN<4>")
	)
	(arc
		(start 335.91246 -263.196832)
		(mid 335.725262 -263.246975)
		(end 335.538064 -263.196832)
		(width 0.088646)
		(layer "In11.Cu")
		(net "M_D_CPU0_SA_DQS_DN<4>")
	)
	(arc
		(start 334.598264 -263.196832)
		(mid 334.315562 -263.12109)
		(end 334.03286 -263.196832)
		(width 0.088646)
		(layer "In11.Cu")
		(net "M_D_CPU0_SA_DQS_DN<4>")
	)
	(arc
		(start 343.056464 -263.196832)
		(mid 342.773762 -263.12109)
		(end 342.49106 -263.196832)
		(width 0.088646)
		(layer "In11.Cu")
		(net "M_D_CPU0_SA_DQS_DN<4>")
	)
	(arc
		(start 337.79206 -263.196832)
		(mid 337.604862 -263.246975)
		(end 337.417664 -263.196832)
		(width 0.088646)
		(layer "In11.Cu")
		(net "M_D_CPU0_SA_DQS_DN<4>")
	)
	(arc
		(start 345.99245 -263.010396)
		(mid 345.917765 -263.040901)
		(end 345.837764 -263.05129)
		(width 0.088646)
		(layer "In11.Cu")
		(net "M_D_CPU0_SA_DQS_DN<4>")
	)
	(arc
		(start 334.03286 -263.196832)
		(mid 333.845662 -263.246975)
		(end 333.658464 -263.196832)
		(width 0.088646)
		(layer "In11.Cu")
		(net "M_D_CPU0_SA_DQS_DN<4>")
	)
	(arc
		(start 339.28685 -263.190736)
		(mid 339.008672 -263.121044)
		(end 338.732114 -263.196832)
		(width 0.088646)
		(layer "In11.Cu")
		(net "M_D_CPU0_SA_DQS_DN<4>")
	)
	(arc
		(start 334.97266 -263.196832)
		(mid 334.785462 -263.246975)
		(end 334.598264 -263.196832)
		(width 0.088646)
		(layer "In11.Cu")
		(net "M_D_CPU0_SA_DQS_DN<4>")
	)
	(arc
		(start 340.61146 -263.196832)
		(mid 340.424262 -263.246975)
		(end 340.237064 -263.196832)
		(width 0.088646)
		(layer "In11.Cu")
		(net "M_D_CPU0_SA_DQS_DN<4>")
	)
	(arc
		(start 344.37066 -263.196832)
		(mid 344.183462 -263.246975)
		(end 343.996264 -263.196832)
		(width 0.088646)
		(layer "In11.Cu")
		(net "M_D_CPU0_SA_DQS_DN<4>")
	)
	(arc
		(start 338.357718 -263.196832)
		(mid 338.080905 -263.120996)
		(end 337.802474 -263.190736)
		(width 0.088646)
		(layer "In11.Cu")
		(net "M_D_CPU0_SA_DQS_DN<4>")
	)
	(arc
		(start 341.55126 -263.196832)
		(mid 341.364062 -263.246975)
		(end 341.176864 -263.196832)
		(width 0.088646)
		(layer "In11.Cu")
		(net "M_D_CPU0_SA_DQS_DN<4>")
	)
	(arc
		(start 344.925904 -263.190736)
		(mid 344.647472 -263.120922)
		(end 344.37066 -263.196832)
		(width 0.088646)
		(layer "In11.Cu")
		(net "M_D_CPU0_SA_DQS_DN<4>")
	)
	(arc
		(start 342.49106 -263.196832)
		(mid 342.303862 -263.246975)
		(end 342.116664 -263.196832)
		(width 0.088646)
		(layer "In11.Cu")
		(net "M_D_CPU0_SA_DQS_DN<4>")
	)
	(arc
		(start 337.417664 -263.196832)
		(mid 337.134962 -263.12109)
		(end 336.85226 -263.196832)
		(width 0.088646)
		(layer "In11.Cu")
		(net "M_D_CPU0_SA_DQS_DN<4>")
	)
	(arc
		(start 343.981532 -263.188196)
		(mid 343.705091 -263.12103)
		(end 343.43086 -263.196832)
		(width 0.088646)
		(layer "In11.Cu")
		(net "M_D_CPU0_SA_DQS_DN<4>")
	)
	(arc
		(start 336.477864 -263.196832)
		(mid 336.195162 -263.12109)
		(end 335.91246 -263.196832)
		(width 0.088646)
		(layer "In11.Cu")
		(net "M_D_CPU0_SA_DQS_DN<4>")
	)
	(arc
		(start 340.222332 -263.188196)
		(mid 339.945891 -263.12103)
		(end 339.67166 -263.196832)
		(width 0.088646)
		(layer "In11.Cu")
		(net "M_D_CPU0_SA_DQS_DN<4>")
	)
	(arc
		(start 345.310714 -263.196832)
		(mid 345.123516 -263.246975)
		(end 344.936318 -263.196832)
		(width 0.088646)
		(layer "In11.Cu")
		(net "M_D_CPU0_SA_DQS_DN<4>")
	)
	(arc
		(start 332.15326 -263.196832)
		(mid 332.063004 -263.234554)
		(end 331.966062 -263.247632)
		(width 0.088646)
		(layer "In11.Cu")
		(net "M_D_CPU0_SA_DQS_DN<4>")
	)
	(arc
		(start 341.162132 -263.188196)
		(mid 340.885691 -263.12103)
		(end 340.61146 -263.196832)
		(width 0.088646)
		(layer "In11.Cu")
		(net "M_D_CPU0_SA_DQS_DN<4>")
	)
	(arc
		(start 343.43086 -263.196832)
		(mid 343.243662 -263.246975)
		(end 343.056464 -263.196832)
		(width 0.088646)
		(layer "In11.Cu")
		(net "M_D_CPU0_SA_DQS_DN<4>")
	)
	(arc
		(start 333.09306 -263.196832)
		(mid 332.905862 -263.246975)
		(end 332.718664 -263.196832)
		(width 0.088646)
		(layer "In11.Cu")
		(net "M_D_CPU0_SA_DQS_DN<4>")
	)
	(arc
		(start 342.101932 -263.188196)
		(mid 341.825491 -263.12103)
		(end 341.55126 -263.196832)
		(width 0.088646)
		(layer "In11.Cu")
		(net "M_D_CPU0_SA_DQS_DN<4>")
	)
	(arc
		(start 333.658464 -263.196832)
		(mid 333.375762 -263.12109)
		(end 333.09306 -263.196832)
		(width 0.088646)
		(layer "In11.Cu")
		(net "M_D_CPU0_SA_DQS_DN<4>")
	)
	(arc
		(start 332.718664 -263.196832)
		(mid 332.435962 -263.12109)
		(end 332.15326 -263.196832)
		(width 0.088646)
		(layer "In11.Cu")
		(net "M_D_CPU0_SA_DQS_DN<4>")
	)
	(segment
		(start 264.729214 -284.016704)
		(end 263.624314 -284.016704)
		(width 0.20066)
		(layer "F.Cu")
		(net "M_D_CPU0_SA_DQS_DN<3>")
	)
	(segment
		(start 256.890266 -284.277816)
		(end 256.629154 -284.016704)
		(width 0.20066)
		(layer "F.Cu")
		(net "M_D_CPU0_SA_DQS_DN<3>")
	)
	(segment
		(start 259.056378 -284.430978)
		(end 258.852162 -284.430978)
		(width 0.20066)
		(layer "F.Cu")
		(net "M_D_CPU0_SA_DQS_DN<3>")
	)
	(segment
		(start 258.040124 -284.703012)
		(end 257.404108 -284.277816)
		(width 0.20066)
		(layer "F.Cu")
		(net "M_D_CPU0_SA_DQS_DN<3>")
	)
	(segment
		(start 262.816594 -284.277816)
		(end 262.40994 -284.277816)
		(width 0.20066)
		(layer "F.Cu")
		(net "M_D_CPU0_SA_DQS_DN<3>")
	)
	(segment
		(start 259.05714 -284.430978)
		(end 259.056378 -284.430978)
		(width 0.101854)
		(layer "F.Cu")
		(net "M_D_CPU0_SA_DQS_DN<3>")
	)
	(segment
		(start 261.536688 -284.441646)
		(end 261.381494 -284.441646)
		(width 0.20066)
		(layer "F.Cu")
		(net "M_D_CPU0_SA_DQS_DN<3>")
	)
	(segment
		(start 261.381494 -284.441646)
		(end 259.067808 -284.441646)
		(width 0.1016)
		(layer "F.Cu")
		(net "M_D_CPU0_SA_DQS_DN<3>")
	)
	(segment
		(start 258.580128 -284.703012)
		(end 258.040124 -284.703012)
		(width 0.20066)
		(layer "F.Cu")
		(net "M_D_CPU0_SA_DQS_DN<3>")
	)
	(segment
		(start 258.852162 -284.430978)
		(end 258.580128 -284.703012)
		(width 0.20066)
		(layer "F.Cu")
		(net "M_D_CPU0_SA_DQS_DN<3>")
	)
	(segment
		(start 263.624314 -284.016704)
		(end 263.077706 -284.016704)
		(width 0.20066)
		(layer "F.Cu")
		(net "M_D_CPU0_SA_DQS_DN<3>")
	)
	(segment
		(start 346.063062 -267.220192)
		(end 346.063062 -267.755878)
		(width 0.20066)
		(layer "F.Cu")
		(net "M_D_CPU0_SA_DQS_DN<3>")
	)
	(segment
		(start 263.077706 -284.016704)
		(end 262.816594 -284.277816)
		(width 0.20066)
		(layer "F.Cu")
		(net "M_D_CPU0_SA_DQS_DN<3>")
	)
	(segment
		(start 262.40994 -284.277816)
		(end 261.984744 -284.703012)
		(width 0.20066)
		(layer "F.Cu")
		(net "M_D_CPU0_SA_DQS_DN<3>")
	)
	(segment
		(start 256.629154 -284.016704)
		(end 256.080514 -284.016704)
		(width 0.20066)
		(layer "F.Cu")
		(net "M_D_CPU0_SA_DQS_DN<3>")
	)
	(segment
		(start 257.404108 -284.277816)
		(end 256.890266 -284.277816)
		(width 0.20066)
		(layer "F.Cu")
		(net "M_D_CPU0_SA_DQS_DN<3>")
	)
	(segment
		(start 261.984744 -284.703012)
		(end 261.798054 -284.703012)
		(width 0.20066)
		(layer "F.Cu")
		(net "M_D_CPU0_SA_DQS_DN<3>")
	)
	(segment
		(start 259.067808 -284.441646)
		(end 259.05714 -284.430978)
		(width 0.101854)
		(layer "F.Cu")
		(net "M_D_CPU0_SA_DQS_DN<3>")
	)
	(segment
		(start 346.063316 -267.219938)
		(end 346.063062 -267.220192)
		(width 0.20066)
		(layer "F.Cu")
		(net "M_D_CPU0_SA_DQS_DN<3>")
	)
	(segment
		(start 261.798054 -284.703012)
		(end 261.536688 -284.441646)
		(width 0.20066)
		(layer "F.Cu")
		(net "M_D_CPU0_SA_DQS_DN<3>")
	)
	(segment
		(start 289.236658 -284.000194)
		(end 289.112198 -283.875734)
		(width 0.18288)
		(layer "In11.Cu")
		(net "M_D_CPU0_SA_DQS_DN<3>")
	)
	(segment
		(start 269.01648 -284.442916)
		(end 268.61008 -284.442916)
		(width 0.18288)
		(layer "In11.Cu")
		(net "M_D_CPU0_SA_DQS_DN<3>")
	)
	(segment
		(start 280.015442 -285.290768)
		(end 279.626314 -285.290768)
		(width 0.18288)
		(layer "In11.Cu")
		(net "M_D_CPU0_SA_DQS_DN<3>")
	)
	(segment
		(start 297.165522 -285.562548)
		(end 296.715434 -285.562548)
		(width 0.18288)
		(layer "In11.Cu")
		(net "M_D_CPU0_SA_DQS_DN<3>")
	)
	(segment
		(start 346.063062 -267.755878)
		(end 346.031312 -267.871702)
		(width 0.088646)
		(layer "In11.Cu")
		(net "M_D_CPU0_SA_DQS_DN<3>")
	)
	(segment
		(start 314.500006 -281.048714)
		(end 313.415172 -281.048714)
		(width 0.18288)
		(layer "In11.Cu")
		(net "M_D_CPU0_SA_DQS_DN<3>")
	)
	(segment
		(start 305.178206 -282.828238)
		(end 304.442622 -282.828238)
		(width 0.18288)
		(layer "In11.Cu")
		(net "M_D_CPU0_SA_DQS_DN<3>")
	)
	(segment
		(start 292.114986 -284.17139)
		(end 291.952426 -284.238954)
		(width 0.18288)
		(layer "In11.Cu")
		(net "M_D_CPU0_SA_DQS_DN<3>")
	)
	(segment
		(start 264.994644 -284.282134)
		(end 264.729214 -284.016704)
		(width 0.18288)
		(layer "In11.Cu")
		(net "M_D_CPU0_SA_DQS_DN<3>")
	)
	(segment
		(start 298.813982 -284.44063)
		(end 298.5389 -284.715712)
		(width 0.18288)
		(layer "In11.Cu")
		(net "M_D_CPU0_SA_DQS_DN<3>")
	)
	(segment
		(start 301.702216 -283.639768)
		(end 300.412658 -284.174692)
		(width 0.18288)
		(layer "In11.Cu")
		(net "M_D_CPU0_SA_DQS_DN<3>")
	)
	(segment
		(start 331.426566 -269.30985)
		(end 331.426566 -269.535148)
		(width 0.088646)
		(layer "In11.Cu")
		(net "M_D_CPU0_SA_DQS_DN<3>")
	)
	(segment
		(start 278.530812 -284.934152)
		(end 278.142446 -284.545786)
		(width 0.18288)
		(layer "In11.Cu")
		(net "M_D_CPU0_SA_DQS_DN<3>")
	)
	(segment
		(start 299.466 -284.712156)
		(end 299.194474 -284.44063)
		(width 0.18288)
		(layer "In11.Cu")
		(net "M_D_CPU0_SA_DQS_DN<3>")
	)
	(segment
		(start 277.966424 -284.545786)
		(end 277.459948 -284.03931)
		(width 0.18288)
		(layer "In11.Cu")
		(net "M_D_CPU0_SA_DQS_DN<3>")
	)
	(segment
		(start 305.975766 -282.828238)
		(end 305.851306 -282.703778)
		(width 0.18288)
		(layer "In11.Cu")
		(net "M_D_CPU0_SA_DQS_DN<3>")
	)
	(segment
		(start 298.5389 -284.715712)
		(end 298.012358 -284.715712)
		(width 0.18288)
		(layer "In11.Cu")
		(net "M_D_CPU0_SA_DQS_DN<3>")
	)
	(segment
		(start 294.713914 -285.290768)
		(end 294.446452 -285.55823)
		(width 0.18288)
		(layer "In11.Cu")
		(net "M_D_CPU0_SA_DQS_DN<3>")
	)
	(segment
		(start 274.807934 -283.91485)
		(end 274.683474 -284.03931)
		(width 0.18288)
		(layer "In11.Cu")
		(net "M_D_CPU0_SA_DQS_DN<3>")
	)
	(segment
		(start 281.22626 -285.543752)
		(end 280.268426 -285.543752)
		(width 0.18288)
		(layer "In11.Cu")
		(net "M_D_CPU0_SA_DQS_DN<3>")
	)
	(segment
		(start 289.112198 -283.875734)
		(end 288.563558 -283.875734)
		(width 0.18288)
		(layer "In11.Cu")
		(net "M_D_CPU0_SA_DQS_DN<3>")
	)
	(segment
		(start 287.765998 -283.875734)
		(end 287.217358 -283.875734)
		(width 0.18288)
		(layer "In11.Cu")
		(net "M_D_CPU0_SA_DQS_DN<3>")
	)
	(segment
		(start 339.297264 -268.080236)
		(end 339.28685 -268.07414)
		(width 0.088646)
		(layer "In11.Cu")
		(net "M_D_CPU0_SA_DQS_DN<3>")
	)
	(segment
		(start 341.176864 -268.080236)
		(end 341.162132 -268.0716)
		(width 0.088646)
		(layer "In11.Cu")
		(net "M_D_CPU0_SA_DQS_DN<3>")
	)
	(segment
		(start 344.936318 -268.080236)
		(end 344.925904 -268.07414)
		(width 0.088646)
		(layer "In11.Cu")
		(net "M_D_CPU0_SA_DQS_DN<3>")
	)
	(segment
		(start 331.426566 -269.535148)
		(end 331.30363 -269.658084)
		(width 0.088646)
		(layer "In11.Cu")
		(net "M_D_CPU0_SA_DQS_DN<3>")
	)
	(segment
		(start 342.116664 -268.080236)
		(end 342.101932 -268.0716)
		(width 0.088646)
		(layer "In11.Cu")
		(net "M_D_CPU0_SA_DQS_DN<3>")
	)
	(segment
		(start 305.302666 -282.703778)
		(end 305.178206 -282.828238)
		(width 0.18288)
		(layer "In11.Cu")
		(net "M_D_CPU0_SA_DQS_DN<3>")
	)
	(segment
		(start 313.415172 -281.048714)
		(end 313.290712 -280.924254)
		(width 0.18288)
		(layer "In11.Cu")
		(net "M_D_CPU0_SA_DQS_DN<3>")
	)
	(segment
		(start 296.042334 -285.438088)
		(end 295.917874 -285.562548)
		(width 0.18288)
		(layer "In11.Cu")
		(net "M_D_CPU0_SA_DQS_DN<3>")
	)
	(segment
		(start 308.20995 -282.224226)
		(end 308.08549 -282.348686)
		(width 0.18288)
		(layer "In11.Cu")
		(net "M_D_CPU0_SA_DQS_DN<3>")
	)
	(segment
		(start 308.08549 -282.348686)
		(end 307.445664 -282.348686)
		(width 0.18288)
		(layer "In11.Cu")
		(net "M_D_CPU0_SA_DQS_DN<3>")
	)
	(segment
		(start 277.459948 -284.03931)
		(end 276.827234 -284.03931)
		(width 0.18288)
		(layer "In11.Cu")
		(net "M_D_CPU0_SA_DQS_DN<3>")
	)
	(segment
		(start 291.375846 -284.000194)
		(end 289.236658 -284.000194)
		(width 0.18288)
		(layer "In11.Cu")
		(net "M_D_CPU0_SA_DQS_DN<3>")
	)
	(segment
		(start 268.362684 -284.690312)
		(end 268.023594 -284.690312)
		(width 0.18288)
		(layer "In11.Cu")
		(net "M_D_CPU0_SA_DQS_DN<3>")
	)
	(segment
		(start 268.023594 -284.690312)
		(end 267.444982 -284.450536)
		(width 0.18288)
		(layer "In11.Cu")
		(net "M_D_CPU0_SA_DQS_DN<3>")
	)
	(segment
		(start 307.445664 -282.348686)
		(end 306.966112 -282.828238)
		(width 0.18288)
		(layer "In11.Cu")
		(net "M_D_CPU0_SA_DQS_DN<3>")
	)
	(segment
		(start 274.683474 -284.03931)
		(end 273.83486 -284.03931)
		(width 0.18288)
		(layer "In11.Cu")
		(net "M_D_CPU0_SA_DQS_DN<3>")
	)
	(segment
		(start 313.290712 -280.924254)
		(end 312.742072 -280.924254)
		(width 0.18288)
		(layer "In11.Cu")
		(net "M_D_CPU0_SA_DQS_DN<3>")
	)
	(segment
		(start 276.827234 -284.03931)
		(end 276.702774 -283.91485)
		(width 0.18288)
		(layer "In11.Cu")
		(net "M_D_CPU0_SA_DQS_DN<3>")
	)
	(segment
		(start 296.590974 -285.438088)
		(end 296.042334 -285.438088)
		(width 0.18288)
		(layer "In11.Cu")
		(net "M_D_CPU0_SA_DQS_DN<3>")
	)
	(segment
		(start 346.031312 -267.871702)
		(end 345.99245 -267.8938)
		(width 0.088646)
		(layer "In11.Cu")
		(net "M_D_CPU0_SA_DQS_DN<3>")
	)
	(segment
		(start 292.622224 -284.381448)
		(end 292.114986 -284.17139)
		(width 0.18288)
		(layer "In11.Cu")
		(net "M_D_CPU0_SA_DQS_DN<3>")
	)
	(segment
		(start 299.194474 -284.44063)
		(end 298.813982 -284.44063)
		(width 0.18288)
		(layer "In11.Cu")
		(net "M_D_CPU0_SA_DQS_DN<3>")
	)
	(segment
		(start 308.88305 -282.348686)
		(end 308.75859 -282.224226)
		(width 0.18288)
		(layer "In11.Cu")
		(net "M_D_CPU0_SA_DQS_DN<3>")
	)
	(segment
		(start 331.734414 -269.002002)
		(end 331.426566 -269.30985)
		(width 0.088646)
		(layer "In11.Cu")
		(net "M_D_CPU0_SA_DQS_DN<3>")
	)
	(segment
		(start 337.802474 -268.07414)
		(end 337.79206 -268.080236)
		(width 0.088646)
		(layer "In11.Cu")
		(net "M_D_CPU0_SA_DQS_DN<3>")
	)
	(segment
		(start 265.677904 -284.282134)
		(end 264.994644 -284.282134)
		(width 0.18288)
		(layer "In11.Cu")
		(net "M_D_CPU0_SA_DQS_DN<3>")
	)
	(segment
		(start 311.0992 -281.048714)
		(end 309.918354 -282.22956)
		(width 0.18288)
		(layer "In11.Cu")
		(net "M_D_CPU0_SA_DQS_DN<3>")
	)
	(segment
		(start 269.276576 -284.703012)
		(end 269.01648 -284.442916)
		(width 0.18288)
		(layer "In11.Cu")
		(net "M_D_CPU0_SA_DQS_DN<3>")
	)
	(segment
		(start 291.952426 -284.238954)
		(end 291.375846 -284.000194)
		(width 0.18288)
		(layer "In11.Cu")
		(net "M_D_CPU0_SA_DQS_DN<3>")
	)
	(segment
		(start 293.196264 -284.754066)
		(end 292.689534 -284.544262)
		(width 0.18288)
		(layer "In11.Cu")
		(net "M_D_CPU0_SA_DQS_DN<3>")
	)
	(segment
		(start 284.371288 -284.703012)
		(end 284.108906 -284.44063)
		(width 0.18288)
		(layer "In11.Cu")
		(net "M_D_CPU0_SA_DQS_DN<3>")
	)
	(segment
		(start 288.439098 -284.000194)
		(end 287.890458 -284.000194)
		(width 0.18288)
		(layer "In11.Cu")
		(net "M_D_CPU0_SA_DQS_DN<3>")
	)
	(segment
		(start 296.715434 -285.562548)
		(end 296.590974 -285.438088)
		(width 0.18288)
		(layer "In11.Cu")
		(net "M_D_CPU0_SA_DQS_DN<3>")
	)
	(segment
		(start 305.851306 -282.703778)
		(end 305.302666 -282.703778)
		(width 0.18288)
		(layer "In11.Cu")
		(net "M_D_CPU0_SA_DQS_DN<3>")
	)
	(segment
		(start 266.094972 -284.109414)
		(end 265.677904 -284.282134)
		(width 0.18288)
		(layer "In11.Cu")
		(net "M_D_CPU0_SA_DQS_DN<3>")
	)
	(segment
		(start 279.626314 -285.290768)
		(end 279.34666 -285.570422)
		(width 0.18288)
		(layer "In11.Cu")
		(net "M_D_CPU0_SA_DQS_DN<3>")
	)
	(segment
		(start 286.544258 -284.000194)
		(end 284.847792 -284.703012)
		(width 0.18288)
		(layer "In11.Cu")
		(net "M_D_CPU0_SA_DQS_DN<3>")
	)
	(segment
		(start 330.92644 -269.598394)
		(end 325.950326 -269.598394)
		(width 0.18288)
		(layer "In11.Cu")
		(net "M_D_CPU0_SA_DQS_DN<3>")
	)
	(segment
		(start 302.483012 -283.639768)
		(end 301.702216 -283.639768)
		(width 0.18288)
		(layer "In11.Cu")
		(net "M_D_CPU0_SA_DQS_DN<3>")
	)
	(segment
		(start 287.092898 -284.000194)
		(end 286.544258 -284.000194)
		(width 0.18288)
		(layer "In11.Cu")
		(net "M_D_CPU0_SA_DQS_DN<3>")
	)
	(segment
		(start 331.734414 -268.754098)
		(end 331.734414 -269.002002)
		(width 0.088646)
		(layer "In11.Cu")
		(net "M_D_CPU0_SA_DQS_DN<3>")
	)
	(segment
		(start 278.142446 -284.545786)
		(end 277.966424 -284.545786)
		(width 0.18288)
		(layer "In11.Cu")
		(net "M_D_CPU0_SA_DQS_DN<3>")
	)
	(segment
		(start 267.444982 -284.450536)
		(end 267.103606 -284.109414)
		(width 0.18288)
		(layer "In11.Cu")
		(net "M_D_CPU0_SA_DQS_DN<3>")
	)
	(segment
		(start 268.61008 -284.442916)
		(end 268.362684 -284.690312)
		(width 0.18288)
		(layer "In11.Cu")
		(net "M_D_CPU0_SA_DQS_DN<3>")
	)
	(segment
		(start 284.108906 -284.44063)
		(end 283.726382 -284.44063)
		(width 0.18288)
		(layer "In11.Cu")
		(net "M_D_CPU0_SA_DQS_DN<3>")
	)
	(segment
		(start 276.154134 -283.91485)
		(end 276.029674 -284.03931)
		(width 0.18288)
		(layer "In11.Cu")
		(net "M_D_CPU0_SA_DQS_DN<3>")
	)
	(segment
		(start 283.212032 -284.720284)
		(end 281.22626 -285.543752)
		(width 0.18288)
		(layer "In11.Cu")
		(net "M_D_CPU0_SA_DQS_DN<3>")
	)
	(segment
		(start 312.617612 -281.048714)
		(end 311.0992 -281.048714)
		(width 0.18288)
		(layer "In11.Cu")
		(net "M_D_CPU0_SA_DQS_DN<3>")
	)
	(segment
		(start 332.015592 -268.47292)
		(end 331.734414 -268.754098)
		(width 0.088646)
		(layer "In11.Cu")
		(net "M_D_CPU0_SA_DQS_DN<3>")
	)
	(segment
		(start 280.268426 -285.543752)
		(end 280.015442 -285.290768)
		(width 0.18288)
		(layer "In11.Cu")
		(net "M_D_CPU0_SA_DQS_DN<3>")
	)
	(segment
		(start 294.000428 -285.55823)
		(end 293.196264 -284.754066)
		(width 0.18288)
		(layer "In11.Cu")
		(net "M_D_CPU0_SA_DQS_DN<3>")
	)
	(segment
		(start 312.742072 -280.924254)
		(end 312.617612 -281.048714)
		(width 0.18288)
		(layer "In11.Cu")
		(net "M_D_CPU0_SA_DQS_DN<3>")
	)
	(segment
		(start 345.564206 -267.934694)
		(end 345.310968 -268.08049)
		(width 0.088646)
		(layer "In11.Cu")
		(net "M_D_CPU0_SA_DQS_DN<3>")
	)
	(segment
		(start 309.918354 -282.22956)
		(end 309.630318 -282.348686)
		(width 0.18288)
		(layer "In11.Cu")
		(net "M_D_CPU0_SA_DQS_DN<3>")
	)
	(segment
		(start 287.890458 -284.000194)
		(end 287.765998 -283.875734)
		(width 0.18288)
		(layer "In11.Cu")
		(net "M_D_CPU0_SA_DQS_DN<3>")
	)
	(segment
		(start 331.30363 -269.658084)
		(end 330.98613 -269.658084)
		(width 0.088646)
		(layer "In11.Cu")
		(net "M_D_CPU0_SA_DQS_DN<3>")
	)
	(segment
		(start 287.217358 -283.875734)
		(end 287.092898 -284.000194)
		(width 0.18288)
		(layer "In11.Cu")
		(net "M_D_CPU0_SA_DQS_DN<3>")
	)
	(segment
		(start 295.097454 -285.290768)
		(end 294.713914 -285.290768)
		(width 0.18288)
		(layer "In11.Cu")
		(net "M_D_CPU0_SA_DQS_DN<3>")
	)
	(segment
		(start 345.837764 -267.934694)
		(end 345.564206 -267.934694)
		(width 0.088646)
		(layer "In11.Cu")
		(net "M_D_CPU0_SA_DQS_DN<3>")
	)
	(segment
		(start 292.689534 -284.544262)
		(end 292.622224 -284.381448)
		(width 0.18288)
		(layer "In11.Cu")
		(net "M_D_CPU0_SA_DQS_DN<3>")
	)
	(segment
		(start 300.412658 -284.174692)
		(end 299.87494 -284.712156)
		(width 0.18288)
		(layer "In11.Cu")
		(net "M_D_CPU0_SA_DQS_DN<3>")
	)
	(segment
		(start 298.012358 -284.715712)
		(end 297.165522 -285.562548)
		(width 0.18288)
		(layer "In11.Cu")
		(net "M_D_CPU0_SA_DQS_DN<3>")
	)
	(segment
		(start 278.530812 -285.110174)
		(end 278.530812 -284.934152)
		(width 0.18288)
		(layer "In11.Cu")
		(net "M_D_CPU0_SA_DQS_DN<3>")
	)
	(segment
		(start 340.237064 -268.080236)
		(end 340.222332 -268.0716)
		(width 0.088646)
		(layer "In11.Cu")
		(net "M_D_CPU0_SA_DQS_DN<3>")
	)
	(segment
		(start 279.34666 -285.570422)
		(end 278.99106 -285.570422)
		(width 0.18288)
		(layer "In11.Cu")
		(net "M_D_CPU0_SA_DQS_DN<3>")
	)
	(segment
		(start 267.103606 -284.109414)
		(end 266.094972 -284.109414)
		(width 0.18288)
		(layer "In11.Cu")
		(net "M_D_CPU0_SA_DQS_DN<3>")
	)
	(segment
		(start 332.015592 -268.324076)
		(end 332.015592 -268.47292)
		(width 0.088646)
		(layer "In11.Cu")
		(net "M_D_CPU0_SA_DQS_DN<3>")
	)
	(segment
		(start 343.996264 -268.080236)
		(end 343.981532 -268.0716)
		(width 0.088646)
		(layer "In11.Cu")
		(net "M_D_CPU0_SA_DQS_DN<3>")
	)
	(segment
		(start 284.847792 -284.703012)
		(end 284.371288 -284.703012)
		(width 0.18288)
		(layer "In11.Cu")
		(net "M_D_CPU0_SA_DQS_DN<3>")
	)
	(segment
		(start 306.966112 -282.828238)
		(end 305.975766 -282.828238)
		(width 0.18288)
		(layer "In11.Cu")
		(net "M_D_CPU0_SA_DQS_DN<3>")
	)
	(segment
		(start 276.029674 -284.03931)
		(end 275.481034 -284.03931)
		(width 0.18288)
		(layer "In11.Cu")
		(net "M_D_CPU0_SA_DQS_DN<3>")
	)
	(segment
		(start 283.446728 -284.720284)
		(end 283.212032 -284.720284)
		(width 0.18288)
		(layer "In11.Cu")
		(net "M_D_CPU0_SA_DQS_DN<3>")
	)
	(segment
		(start 276.702774 -283.91485)
		(end 276.154134 -283.91485)
		(width 0.18288)
		(layer "In11.Cu")
		(net "M_D_CPU0_SA_DQS_DN<3>")
	)
	(segment
		(start 345.310968 -268.08049)
		(end 345.310714 -268.080236)
		(width 0.088646)
		(layer "In11.Cu")
		(net "M_D_CPU0_SA_DQS_DN<3>")
	)
	(segment
		(start 309.630318 -282.348686)
		(end 308.88305 -282.348686)
		(width 0.18288)
		(layer "In11.Cu")
		(net "M_D_CPU0_SA_DQS_DN<3>")
	)
	(segment
		(start 288.563558 -283.875734)
		(end 288.439098 -284.000194)
		(width 0.18288)
		(layer "In11.Cu")
		(net "M_D_CPU0_SA_DQS_DN<3>")
	)
	(segment
		(start 308.75859 -282.224226)
		(end 308.20995 -282.224226)
		(width 0.18288)
		(layer "In11.Cu")
		(net "M_D_CPU0_SA_DQS_DN<3>")
	)
	(segment
		(start 294.446452 -285.55823)
		(end 294.000428 -285.55823)
		(width 0.18288)
		(layer "In11.Cu")
		(net "M_D_CPU0_SA_DQS_DN<3>")
	)
	(segment
		(start 275.356574 -283.91485)
		(end 274.807934 -283.91485)
		(width 0.18288)
		(layer "In11.Cu")
		(net "M_D_CPU0_SA_DQS_DN<3>")
	)
	(segment
		(start 275.481034 -284.03931)
		(end 275.356574 -283.91485)
		(width 0.18288)
		(layer "In11.Cu")
		(net "M_D_CPU0_SA_DQS_DN<3>")
	)
	(segment
		(start 304.442622 -282.828238)
		(end 302.483012 -283.639768)
		(width 0.18288)
		(layer "In11.Cu")
		(net "M_D_CPU0_SA_DQS_DN<3>")
	)
	(segment
		(start 295.917874 -285.562548)
		(end 295.369234 -285.562548)
		(width 0.18288)
		(layer "In11.Cu")
		(net "M_D_CPU0_SA_DQS_DN<3>")
	)
	(segment
		(start 278.99106 -285.570422)
		(end 278.530812 -285.110174)
		(width 0.18288)
		(layer "In11.Cu")
		(net "M_D_CPU0_SA_DQS_DN<3>")
	)
	(segment
		(start 325.950326 -269.598394)
		(end 314.500006 -281.048714)
		(width 0.18288)
		(layer "In11.Cu")
		(net "M_D_CPU0_SA_DQS_DN<3>")
	)
	(segment
		(start 330.98613 -269.658084)
		(end 330.92644 -269.598394)
		(width 0.088646)
		(layer "In11.Cu")
		(net "M_D_CPU0_SA_DQS_DN<3>")
	)
	(segment
		(start 299.87494 -284.712156)
		(end 299.466 -284.712156)
		(width 0.18288)
		(layer "In11.Cu")
		(net "M_D_CPU0_SA_DQS_DN<3>")
	)
	(segment
		(start 272.23339 -284.703012)
		(end 269.276576 -284.703012)
		(width 0.18288)
		(layer "In11.Cu")
		(net "M_D_CPU0_SA_DQS_DN<3>")
	)
	(segment
		(start 283.726382 -284.44063)
		(end 283.446728 -284.720284)
		(width 0.18288)
		(layer "In11.Cu")
		(net "M_D_CPU0_SA_DQS_DN<3>")
	)
	(segment
		(start 273.83486 -284.03931)
		(end 272.23339 -284.703012)
		(width 0.18288)
		(layer "In11.Cu")
		(net "M_D_CPU0_SA_DQS_DN<3>")
	)
	(segment
		(start 295.369234 -285.562548)
		(end 295.097454 -285.290768)
		(width 0.18288)
		(layer "In11.Cu")
		(net "M_D_CPU0_SA_DQS_DN<3>")
	)
	(arc
		(start 339.28685 -268.07414)
		(mid 339.008672 -268.004417)
		(end 338.732114 -268.080236)
		(width 0.088646)
		(layer "In11.Cu")
		(net "M_D_CPU0_SA_DQS_DN<3>")
	)
	(arc
		(start 343.981532 -268.0716)
		(mid 343.705057 -268.00428)
		(end 343.43086 -268.080236)
		(width 0.088646)
		(layer "In11.Cu")
		(net "M_D_CPU0_SA_DQS_DN<3>")
	)
	(arc
		(start 343.43086 -268.080236)
		(mid 343.243662 -268.130379)
		(end 343.056464 -268.080236)
		(width 0.088646)
		(layer "In11.Cu")
		(net "M_D_CPU0_SA_DQS_DN<3>")
	)
	(arc
		(start 336.477864 -268.080236)
		(mid 336.195162 -268.00446)
		(end 335.91246 -268.080236)
		(width 0.088646)
		(layer "In11.Cu")
		(net "M_D_CPU0_SA_DQS_DN<3>")
	)
	(arc
		(start 336.85226 -268.080236)
		(mid 336.665062 -268.130379)
		(end 336.477864 -268.080236)
		(width 0.088646)
		(layer "In11.Cu")
		(net "M_D_CPU0_SA_DQS_DN<3>")
	)
	(arc
		(start 344.37066 -268.080236)
		(mid 344.183462 -268.130379)
		(end 343.996264 -268.080236)
		(width 0.088646)
		(layer "In11.Cu")
		(net "M_D_CPU0_SA_DQS_DN<3>")
	)
	(arc
		(start 339.67166 -268.080236)
		(mid 339.484462 -268.130379)
		(end 339.297264 -268.080236)
		(width 0.088646)
		(layer "In11.Cu")
		(net "M_D_CPU0_SA_DQS_DN<3>")
	)
	(arc
		(start 340.222332 -268.0716)
		(mid 339.945857 -268.00428)
		(end 339.67166 -268.080236)
		(width 0.088646)
		(layer "In11.Cu")
		(net "M_D_CPU0_SA_DQS_DN<3>")
	)
	(arc
		(start 343.056464 -268.080236)
		(mid 342.773762 -268.00446)
		(end 342.49106 -268.080236)
		(width 0.088646)
		(layer "In11.Cu")
		(net "M_D_CPU0_SA_DQS_DN<3>")
	)
	(arc
		(start 344.925904 -268.07414)
		(mid 344.647472 -268.004294)
		(end 344.37066 -268.080236)
		(width 0.088646)
		(layer "In11.Cu")
		(net "M_D_CPU0_SA_DQS_DN<3>")
	)
	(arc
		(start 333.1337 -268.058646)
		(mid 332.926075 -268.111745)
		(end 332.713584 -268.083792)
		(width 0.088646)
		(layer "In11.Cu")
		(net "M_D_CPU0_SA_DQS_DN<3>")
	)
	(arc
		(start 338.732114 -268.080236)
		(mid 338.544916 -268.130379)
		(end 338.357718 -268.080236)
		(width 0.088646)
		(layer "In11.Cu")
		(net "M_D_CPU0_SA_DQS_DN<3>")
	)
	(arc
		(start 340.61146 -268.080236)
		(mid 340.424262 -268.130379)
		(end 340.237064 -268.080236)
		(width 0.088646)
		(layer "In11.Cu")
		(net "M_D_CPU0_SA_DQS_DN<3>")
	)
	(arc
		(start 342.101932 -268.0716)
		(mid 341.825457 -268.00428)
		(end 341.55126 -268.080236)
		(width 0.088646)
		(layer "In11.Cu")
		(net "M_D_CPU0_SA_DQS_DN<3>")
	)
	(arc
		(start 335.538064 -268.080236)
		(mid 335.255362 -268.00446)
		(end 334.97266 -268.080236)
		(width 0.088646)
		(layer "In11.Cu")
		(net "M_D_CPU0_SA_DQS_DN<3>")
	)
	(arc
		(start 334.03286 -268.080236)
		(mid 333.845662 -268.130379)
		(end 333.658464 -268.080236)
		(width 0.088646)
		(layer "In11.Cu")
		(net "M_D_CPU0_SA_DQS_DN<3>")
	)
	(arc
		(start 338.357718 -268.080236)
		(mid 338.080905 -268.004366)
		(end 337.802474 -268.07414)
		(width 0.088646)
		(layer "In11.Cu")
		(net "M_D_CPU0_SA_DQS_DN<3>")
	)
	(arc
		(start 337.79206 -268.080236)
		(mid 337.604862 -268.130379)
		(end 337.417664 -268.080236)
		(width 0.088646)
		(layer "In11.Cu")
		(net "M_D_CPU0_SA_DQS_DN<3>")
	)
	(arc
		(start 332.246224 -268.049248)
		(mid 332.080935 -268.144709)
		(end 332.015592 -268.324076)
		(width 0.088646)
		(layer "In11.Cu")
		(net "M_D_CPU0_SA_DQS_DN<3>")
	)
	(arc
		(start 341.55126 -268.080236)
		(mid 341.364062 -268.130379)
		(end 341.176864 -268.080236)
		(width 0.088646)
		(layer "In11.Cu")
		(net "M_D_CPU0_SA_DQS_DN<3>")
	)
	(arc
		(start 335.91246 -268.080236)
		(mid 335.725262 -268.130379)
		(end 335.538064 -268.080236)
		(width 0.088646)
		(layer "In11.Cu")
		(net "M_D_CPU0_SA_DQS_DN<3>")
	)
	(arc
		(start 337.417664 -268.080236)
		(mid 337.134962 -268.00446)
		(end 336.85226 -268.080236)
		(width 0.088646)
		(layer "In11.Cu")
		(net "M_D_CPU0_SA_DQS_DN<3>")
	)
	(arc
		(start 341.162132 -268.0716)
		(mid 340.885657 -268.00428)
		(end 340.61146 -268.080236)
		(width 0.088646)
		(layer "In11.Cu")
		(net "M_D_CPU0_SA_DQS_DN<3>")
	)
	(arc
		(start 345.310714 -268.080236)
		(mid 345.123516 -268.130379)
		(end 344.936318 -268.080236)
		(width 0.088646)
		(layer "In11.Cu")
		(net "M_D_CPU0_SA_DQS_DN<3>")
	)
	(arc
		(start 334.598264 -268.080236)
		(mid 334.315562 -268.00446)
		(end 334.03286 -268.080236)
		(width 0.088646)
		(layer "In11.Cu")
		(net "M_D_CPU0_SA_DQS_DN<3>")
	)
	(arc
		(start 334.97266 -268.080236)
		(mid 334.785462 -268.130379)
		(end 334.598264 -268.080236)
		(width 0.088646)
		(layer "In11.Cu")
		(net "M_D_CPU0_SA_DQS_DN<3>")
	)
	(arc
		(start 332.713584 -268.083792)
		(mid 332.482054 -268.037412)
		(end 332.246224 -268.049248)
		(width 0.088646)
		(layer "In11.Cu")
		(net "M_D_CPU0_SA_DQS_DN<3>")
	)
	(arc
		(start 333.658464 -268.080236)
		(mid 333.398742 -268.00481)
		(end 333.1337 -268.058646)
		(width 0.088646)
		(layer "In11.Cu")
		(net "M_D_CPU0_SA_DQS_DN<3>")
	)
	(arc
		(start 345.99245 -267.8938)
		(mid 345.917765 -267.924305)
		(end 345.837764 -267.934694)
		(width 0.088646)
		(layer "In11.Cu")
		(net "M_D_CPU0_SA_DQS_DN<3>")
	)
	(arc
		(start 342.49106 -268.080236)
		(mid 342.303862 -268.130379)
		(end 342.116664 -268.080236)
		(width 0.088646)
		(layer "In11.Cu")
		(net "M_D_CPU0_SA_DQS_DN<3>")
	)
	(segment
		(start 262.40994 -293.62781)
		(end 261.984744 -294.053006)
		(width 0.20066)
		(layer "F.Cu")
		(net "M_D_CPU0_SA_DQS_DN<2>")
	)
	(segment
		(start 261.536688 -293.79164)
		(end 261.381494 -293.79164)
		(width 0.20066)
		(layer "F.Cu")
		(net "M_D_CPU0_SA_DQS_DN<2>")
	)
	(segment
		(start 258.852162 -293.780972)
		(end 258.580128 -294.053006)
		(width 0.20066)
		(layer "F.Cu")
		(net "M_D_CPU0_SA_DQS_DN<2>")
	)
	(segment
		(start 259.067808 -293.79164)
		(end 259.05714 -293.780972)
		(width 0.101854)
		(layer "F.Cu")
		(net "M_D_CPU0_SA_DQS_DN<2>")
	)
	(segment
		(start 263.077706 -293.366698)
		(end 262.816594 -293.62781)
		(width 0.20066)
		(layer "F.Cu")
		(net "M_D_CPU0_SA_DQS_DN<2>")
	)
	(segment
		(start 257.404108 -293.62781)
		(end 256.890266 -293.62781)
		(width 0.20066)
		(layer "F.Cu")
		(net "M_D_CPU0_SA_DQS_DN<2>")
	)
	(segment
		(start 261.381494 -293.79164)
		(end 259.067808 -293.79164)
		(width 0.1016)
		(layer "F.Cu")
		(net "M_D_CPU0_SA_DQS_DN<2>")
	)
	(segment
		(start 264.729214 -293.366698)
		(end 263.624314 -293.366698)
		(width 0.20066)
		(layer "F.Cu")
		(net "M_D_CPU0_SA_DQS_DN<2>")
	)
	(segment
		(start 258.040124 -294.053006)
		(end 257.404108 -293.62781)
		(width 0.20066)
		(layer "F.Cu")
		(net "M_D_CPU0_SA_DQS_DN<2>")
	)
	(segment
		(start 259.05714 -293.780972)
		(end 259.056378 -293.780972)
		(width 0.101854)
		(layer "F.Cu")
		(net "M_D_CPU0_SA_DQS_DN<2>")
	)
	(segment
		(start 256.629154 -293.366698)
		(end 256.080514 -293.366698)
		(width 0.20066)
		(layer "F.Cu")
		(net "M_D_CPU0_SA_DQS_DN<2>")
	)
	(segment
		(start 261.984744 -294.053006)
		(end 261.798054 -294.053006)
		(width 0.20066)
		(layer "F.Cu")
		(net "M_D_CPU0_SA_DQS_DN<2>")
	)
	(segment
		(start 262.816594 -293.62781)
		(end 262.40994 -293.62781)
		(width 0.20066)
		(layer "F.Cu")
		(net "M_D_CPU0_SA_DQS_DN<2>")
	)
	(segment
		(start 256.890266 -293.62781)
		(end 256.629154 -293.366698)
		(width 0.20066)
		(layer "F.Cu")
		(net "M_D_CPU0_SA_DQS_DN<2>")
	)
	(segment
		(start 258.580128 -294.053006)
		(end 258.040124 -294.053006)
		(width 0.20066)
		(layer "F.Cu")
		(net "M_D_CPU0_SA_DQS_DN<2>")
	)
	(segment
		(start 263.624314 -293.366698)
		(end 263.077706 -293.366698)
		(width 0.20066)
		(layer "F.Cu")
		(net "M_D_CPU0_SA_DQS_DN<2>")
	)
	(segment
		(start 261.798054 -294.053006)
		(end 261.536688 -293.79164)
		(width 0.20066)
		(layer "F.Cu")
		(net "M_D_CPU0_SA_DQS_DN<2>")
	)
	(segment
		(start 259.056378 -293.780972)
		(end 258.852162 -293.780972)
		(width 0.20066)
		(layer "F.Cu")
		(net "M_D_CPU0_SA_DQS_DN<2>")
	)
	(arc
		(start 346.063316 -272.103342)
		(mid 346.063252 -272.371312)
		(end 346.063062 -272.639282)
		(width 0.20066)
		(layer "F.Cu")
		(net "M_D_CPU0_SA_DQS_DN<2>")
	)
	(segment
		(start 308.577996 -291.127434)
		(end 308.453536 -291.251894)
		(width 0.18288)
		(layer "In11.Cu")
		(net "M_D_CPU0_SA_DQS_DN<2>")
	)
	(segment
		(start 331.087984 -275.673058)
		(end 331.028294 -275.613368)
		(width 0.088646)
		(layer "In11.Cu")
		(net "M_D_CPU0_SA_DQS_DN<2>")
	)
	(segment
		(start 281.256232 -296.586402)
		(end 280.332942 -296.586402)
		(width 0.18288)
		(layer "In11.Cu")
		(net "M_D_CPU0_SA_DQS_DN<2>")
	)
	(segment
		(start 332.97622 -273.053302)
		(end 332.608936 -273.420586)
		(width 0.088646)
		(layer "In11.Cu")
		(net "M_D_CPU0_SA_DQS_DN<2>")
	)
	(segment
		(start 310.970422 -291.042344)
		(end 310.463692 -291.251894)
		(width 0.18288)
		(layer "In11.Cu")
		(net "M_D_CPU0_SA_DQS_DN<2>")
	)
	(segment
		(start 331.028294 -275.613368)
		(end 328.653648 -275.613368)
		(width 0.18288)
		(layer "In11.Cu")
		(net "M_D_CPU0_SA_DQS_DN<2>")
	)
	(segment
		(start 291.202364 -296.496486)
		(end 290.694618 -295.98874)
		(width 0.18288)
		(layer "In11.Cu")
		(net "M_D_CPU0_SA_DQS_DN<2>")
	)
	(segment
		(start 294.05707 -296.623486)
		(end 293.711376 -296.277792)
		(width 0.18288)
		(layer "In11.Cu")
		(net "M_D_CPU0_SA_DQS_DN<2>")
	)
	(segment
		(start 277.707852 -297.200574)
		(end 277.329392 -297.200574)
		(width 0.18288)
		(layer "In11.Cu")
		(net "M_D_CPU0_SA_DQS_DN<2>")
	)
	(segment
		(start 298.533566 -295.762172)
		(end 297.884342 -295.762172)
		(width 0.18288)
		(layer "In11.Cu")
		(net "M_D_CPU0_SA_DQS_DN<2>")
	)
	(segment
		(start 286.425132 -295.770554)
		(end 286.300672 -295.646094)
		(width 0.18288)
		(layer "In11.Cu")
		(net "M_D_CPU0_SA_DQS_DN<2>")
	)
	(segment
		(start 285.752032 -295.646094)
		(end 285.627572 -295.770554)
		(width 0.18288)
		(layer "In11.Cu")
		(net "M_D_CPU0_SA_DQS_DN<2>")
	)
	(segment
		(start 314.634372 -289.632644)
		(end 314.634372 -290.129722)
		(width 0.18288)
		(layer "In11.Cu")
		(net "M_D_CPU0_SA_DQS_DN<2>")
	)
	(segment
		(start 290.130484 -295.424606)
		(end 289.742626 -295.036748)
		(width 0.18288)
		(layer "In11.Cu")
		(net "M_D_CPU0_SA_DQS_DN<2>")
	)
	(segment
		(start 273.306286 -294.549068)
		(end 273.238722 -294.386254)
		(width 0.18288)
		(layer "In11.Cu")
		(net "M_D_CPU0_SA_DQS_DN<2>")
	)
	(segment
		(start 305.716686 -292.51021)
		(end 305.649376 -292.673278)
		(width 0.18288)
		(layer "In11.Cu")
		(net "M_D_CPU0_SA_DQS_DN<2>")
	)
	(segment
		(start 285.627572 -295.770554)
		(end 284.383988 -295.770554)
		(width 0.18288)
		(layer "In11.Cu")
		(net "M_D_CPU0_SA_DQS_DN<2>")
	)
	(segment
		(start 278.939498 -296.632376)
		(end 277.707852 -297.200574)
		(width 0.18288)
		(layer "In11.Cu")
		(net "M_D_CPU0_SA_DQS_DN<2>")
	)
	(segment
		(start 274.381214 -294.993822)
		(end 274.380452 -294.993568)
		(width 0.18288)
		(layer "In11.Cu")
		(net "M_D_CPU0_SA_DQS_DN<2>")
	)
	(segment
		(start 287.029906 -295.770554)
		(end 286.425132 -295.770554)
		(width 0.18288)
		(layer "In11.Cu")
		(net "M_D_CPU0_SA_DQS_DN<2>")
	)
	(segment
		(start 333.658464 -272.96364)
		(end 333.64805 -272.957544)
		(width 0.088646)
		(layer "In11.Cu")
		(net "M_D_CPU0_SA_DQS_DN<2>")
	)
	(segment
		(start 280.087578 -296.341038)
		(end 279.618694 -296.341038)
		(width 0.18288)
		(layer "In11.Cu")
		(net "M_D_CPU0_SA_DQS_DN<2>")
	)
	(segment
		(start 269.11935 -293.791132)
		(end 268.611858 -293.791132)
		(width 0.18288)
		(layer "In11.Cu")
		(net "M_D_CPU0_SA_DQS_DN<2>")
	)
	(segment
		(start 332.976474 -273.052794)
		(end 332.97622 -273.053302)
		(width 0.088646)
		(layer "In11.Cu")
		(net "M_D_CPU0_SA_DQS_DN<2>")
	)
	(segment
		(start 311.707784 -290.737036)
		(end 311.545224 -290.669726)
		(width 0.18288)
		(layer "In11.Cu")
		(net "M_D_CPU0_SA_DQS_DN<2>")
	)
	(segment
		(start 265.932158 -293.389304)
		(end 265.344148 -293.63289)
		(width 0.18288)
		(layer "In11.Cu")
		(net "M_D_CPU0_SA_DQS_DN<2>")
	)
	(segment
		(start 283.221176 -295.772332)
		(end 281.256232 -296.586402)
		(width 0.18288)
		(layer "In11.Cu")
		(net "M_D_CPU0_SA_DQS_DN<2>")
	)
	(segment
		(start 306.893214 -292.157658)
		(end 306.386484 -292.367462)
		(width 0.18288)
		(layer "In11.Cu")
		(net "M_D_CPU0_SA_DQS_DN<2>")
	)
	(segment
		(start 331.732382 -274.561046)
		(end 331.732382 -275.252942)
		(width 0.088646)
		(layer "In11.Cu")
		(net "M_D_CPU0_SA_DQS_DN<2>")
	)
	(segment
		(start 306.223924 -292.300152)
		(end 305.716686 -292.51021)
		(width 0.18288)
		(layer "In11.Cu")
		(net "M_D_CPU0_SA_DQS_DN<2>")
	)
	(segment
		(start 332.608936 -273.684492)
		(end 331.732382 -274.561046)
		(width 0.088646)
		(layer "In11.Cu")
		(net "M_D_CPU0_SA_DQS_DN<2>")
	)
	(segment
		(start 343.996264 -272.96364)
		(end 343.981532 -272.955004)
		(width 0.088646)
		(layer "In11.Cu")
		(net "M_D_CPU0_SA_DQS_DN<2>")
	)
	(segment
		(start 265.344148 -293.63289)
		(end 264.995406 -293.63289)
		(width 0.18288)
		(layer "In11.Cu")
		(net "M_D_CPU0_SA_DQS_DN<2>")
	)
	(segment
		(start 292.289738 -295.91762)
		(end 291.710872 -296.496486)
		(width 0.18288)
		(layer "In11.Cu")
		(net "M_D_CPU0_SA_DQS_DN<2>")
	)
	(segment
		(start 268.337284 -294.065706)
		(end 267.851128 -294.065706)
		(width 0.18288)
		(layer "In11.Cu")
		(net "M_D_CPU0_SA_DQS_DN<2>")
	)
	(segment
		(start 306.893722 -292.15715)
		(end 306.893214 -292.157658)
		(width 0.18288)
		(layer "In11.Cu")
		(net "M_D_CPU0_SA_DQS_DN<2>")
	)
	(segment
		(start 331.732382 -275.252942)
		(end 331.312266 -275.673058)
		(width 0.088646)
		(layer "In11.Cu")
		(net "M_D_CPU0_SA_DQS_DN<2>")
	)
	(segment
		(start 267.478002 -293.69258)
		(end 266.744958 -293.389304)
		(width 0.18288)
		(layer "In11.Cu")
		(net "M_D_CPU0_SA_DQS_DN<2>")
	)
	(segment
		(start 264.995406 -293.63289)
		(end 264.729214 -293.366698)
		(width 0.18288)
		(layer "In11.Cu")
		(net "M_D_CPU0_SA_DQS_DN<2>")
	)
	(segment
		(start 301.870872 -294.446706)
		(end 301.836582 -294.619172)
		(width 0.18288)
		(layer "In11.Cu")
		(net "M_D_CPU0_SA_DQS_DN<2>")
	)
	(segment
		(start 308.453536 -291.251894)
		(end 307.799232 -291.251894)
		(width 0.18288)
		(layer "In11.Cu")
		(net "M_D_CPU0_SA_DQS_DN<2>")
	)
	(segment
		(start 295.360598 -296.606214)
		(end 295.095422 -296.341038)
		(width 0.18288)
		(layer "In11.Cu")
		(net "M_D_CPU0_SA_DQS_DN<2>")
	)
	(segment
		(start 310.463692 -291.251894)
		(end 309.251096 -291.251894)
		(width 0.18288)
		(layer "In11.Cu")
		(net "M_D_CPU0_SA_DQS_DN<2>")
	)
	(segment
		(start 307.799232 -291.251894)
		(end 306.893722 -292.15715)
		(width 0.18288)
		(layer "In11.Cu")
		(net "M_D_CPU0_SA_DQS_DN<2>")
	)
	(segment
		(start 314.634372 -290.129722)
		(end 314.353448 -290.410646)
		(width 0.18288)
		(layer "In11.Cu")
		(net "M_D_CPU0_SA_DQS_DN<2>")
	)
	(segment
		(start 345.310968 -272.963894)
		(end 345.310714 -272.96364)
		(width 0.088646)
		(layer "In11.Cu")
		(net "M_D_CPU0_SA_DQS_DN<2>")
	)
	(segment
		(start 309.251096 -291.251894)
		(end 309.126636 -291.127434)
		(width 0.18288)
		(layer "In11.Cu")
		(net "M_D_CPU0_SA_DQS_DN<2>")
	)
	(segment
		(start 302.50003 -294.175942)
		(end 302.32731 -294.141652)
		(width 0.18288)
		(layer "In11.Cu")
		(net "M_D_CPU0_SA_DQS_DN<2>")
	)
	(segment
		(start 279.618694 -296.341038)
		(end 279.327356 -296.632376)
		(width 0.18288)
		(layer "In11.Cu")
		(net "M_D_CPU0_SA_DQS_DN<2>")
	)
	(segment
		(start 284.105858 -295.492424)
		(end 283.724858 -295.492424)
		(width 0.18288)
		(layer "In11.Cu")
		(net "M_D_CPU0_SA_DQS_DN<2>")
	)
	(segment
		(start 311.037986 -290.87953)
		(end 310.970422 -291.042344)
		(width 0.18288)
		(layer "In11.Cu")
		(net "M_D_CPU0_SA_DQS_DN<2>")
	)
	(segment
		(start 332.608936 -273.420586)
		(end 332.608936 -273.684492)
		(width 0.088646)
		(layer "In11.Cu")
		(net "M_D_CPU0_SA_DQS_DN<2>")
	)
	(segment
		(start 300.014132 -295.755314)
		(end 299.479716 -295.755314)
		(width 0.18288)
		(layer "In11.Cu")
		(net "M_D_CPU0_SA_DQS_DN<2>")
	)
	(segment
		(start 345.564206 -272.818098)
		(end 345.310968 -272.963894)
		(width 0.088646)
		(layer "In11.Cu")
		(net "M_D_CPU0_SA_DQS_DN<2>")
	)
	(segment
		(start 305.649376 -292.673278)
		(end 303.279048 -293.655496)
		(width 0.18288)
		(layer "In11.Cu")
		(net "M_D_CPU0_SA_DQS_DN<2>")
	)
	(segment
		(start 279.327356 -296.632376)
		(end 278.939498 -296.632376)
		(width 0.18288)
		(layer "In11.Cu")
		(net "M_D_CPU0_SA_DQS_DN<2>")
	)
	(segment
		(start 283.724858 -295.492424)
		(end 283.44495 -295.772332)
		(width 0.18288)
		(layer "In11.Cu")
		(net "M_D_CPU0_SA_DQS_DN<2>")
	)
	(segment
		(start 269.362428 -294.03421)
		(end 269.11935 -293.791132)
		(width 0.18288)
		(layer "In11.Cu")
		(net "M_D_CPU0_SA_DQS_DN<2>")
	)
	(segment
		(start 334.983328 -272.957544)
		(end 334.972914 -272.96364)
		(width 0.088646)
		(layer "In11.Cu")
		(net "M_D_CPU0_SA_DQS_DN<2>")
	)
	(segment
		(start 294.708834 -296.341038)
		(end 294.426386 -296.623486)
		(width 0.18288)
		(layer "In11.Cu")
		(net "M_D_CPU0_SA_DQS_DN<2>")
	)
	(segment
		(start 272.568924 -294.24376)
		(end 272.062194 -294.03421)
		(width 0.18288)
		(layer "In11.Cu")
		(net "M_D_CPU0_SA_DQS_DN<2>")
	)
	(segment
		(start 290.694618 -295.98874)
		(end 290.694618 -295.812718)
		(width 0.18288)
		(layer "In11.Cu")
		(net "M_D_CPU0_SA_DQS_DN<2>")
	)
	(segment
		(start 337.802474 -272.957544)
		(end 337.79206 -272.96364)
		(width 0.088646)
		(layer "In11.Cu")
		(net "M_D_CPU0_SA_DQS_DN<2>")
	)
	(segment
		(start 267.851128 -294.065706)
		(end 267.478002 -293.69258)
		(width 0.18288)
		(layer "In11.Cu")
		(net "M_D_CPU0_SA_DQS_DN<2>")
	)
	(segment
		(start 303.279048 -293.655496)
		(end 303.277524 -293.656258)
		(width 0.18288)
		(layer "In11.Cu")
		(net "M_D_CPU0_SA_DQS_DN<2>")
	)
	(segment
		(start 299.479716 -295.755314)
		(end 299.215302 -295.4909)
		(width 0.18288)
		(layer "In11.Cu")
		(net "M_D_CPU0_SA_DQS_DN<2>")
	)
	(segment
		(start 344.936318 -272.96364)
		(end 344.925904 -272.957544)
		(width 0.088646)
		(layer "In11.Cu")
		(net "M_D_CPU0_SA_DQS_DN<2>")
	)
	(segment
		(start 291.710872 -296.496486)
		(end 291.202364 -296.496486)
		(width 0.18288)
		(layer "In11.Cu")
		(net "M_D_CPU0_SA_DQS_DN<2>")
	)
	(segment
		(start 270.715994 -294.03421)
		(end 269.362428 -294.03421)
		(width 0.18288)
		(layer "In11.Cu")
		(net "M_D_CPU0_SA_DQS_DN<2>")
	)
	(segment
		(start 342.116664 -272.96364)
		(end 342.101932 -272.955004)
		(width 0.088646)
		(layer "In11.Cu")
		(net "M_D_CPU0_SA_DQS_DN<2>")
	)
	(segment
		(start 272.062194 -294.03421)
		(end 271.513554 -294.03421)
		(width 0.18288)
		(layer "In11.Cu")
		(net "M_D_CPU0_SA_DQS_DN<2>")
	)
	(segment
		(start 331.312266 -275.673058)
		(end 331.087984 -275.673058)
		(width 0.088646)
		(layer "In11.Cu")
		(net "M_D_CPU0_SA_DQS_DN<2>")
	)
	(segment
		(start 297.04792 -296.319448)
		(end 296.355516 -296.606214)
		(width 0.18288)
		(layer "In11.Cu")
		(net "M_D_CPU0_SA_DQS_DN<2>")
	)
	(segment
		(start 309.126636 -291.127434)
		(end 308.577996 -291.127434)
		(width 0.18288)
		(layer "In11.Cu")
		(net "M_D_CPU0_SA_DQS_DN<2>")
	)
	(segment
		(start 271.513554 -294.03421)
		(end 271.389094 -293.90975)
		(width 0.18288)
		(layer "In11.Cu")
		(net "M_D_CPU0_SA_DQS_DN<2>")
	)
	(segment
		(start 298.804838 -295.4909)
		(end 298.533566 -295.762172)
		(width 0.18288)
		(layer "In11.Cu")
		(net "M_D_CPU0_SA_DQS_DN<2>")
	)
	(segment
		(start 272.731484 -294.17645)
		(end 272.568924 -294.24376)
		(width 0.18288)
		(layer "In11.Cu")
		(net "M_D_CPU0_SA_DQS_DN<2>")
	)
	(segment
		(start 302.32731 -294.141652)
		(end 301.870872 -294.446706)
		(width 0.18288)
		(layer "In11.Cu")
		(net "M_D_CPU0_SA_DQS_DN<2>")
	)
	(segment
		(start 275.414232 -295.684194)
		(end 274.381214 -294.993822)
		(width 0.18288)
		(layer "In11.Cu")
		(net "M_D_CPU0_SA_DQS_DN<2>")
	)
	(segment
		(start 303.277524 -293.656258)
		(end 302.50003 -294.175942)
		(width 0.18288)
		(layer "In11.Cu")
		(net "M_D_CPU0_SA_DQS_DN<2>")
	)
	(segment
		(start 273.238722 -294.386254)
		(end 272.731484 -294.17645)
		(width 0.18288)
		(layer "In11.Cu")
		(net "M_D_CPU0_SA_DQS_DN<2>")
	)
	(segment
		(start 276.648926 -296.918888)
		(end 275.414232 -295.684194)
		(width 0.18288)
		(layer "In11.Cu")
		(net "M_D_CPU0_SA_DQS_DN<2>")
	)
	(segment
		(start 292.843204 -295.91762)
		(end 292.289738 -295.91762)
		(width 0.18288)
		(layer "In11.Cu")
		(net "M_D_CPU0_SA_DQS_DN<2>")
	)
	(segment
		(start 290.306506 -295.424606)
		(end 290.130484 -295.424606)
		(width 0.18288)
		(layer "In11.Cu")
		(net "M_D_CPU0_SA_DQS_DN<2>")
	)
	(segment
		(start 287.651952 -295.512744)
		(end 287.029906 -295.770554)
		(width 0.18288)
		(layer "In11.Cu")
		(net "M_D_CPU0_SA_DQS_DN<2>")
	)
	(segment
		(start 296.355516 -296.606214)
		(end 295.360598 -296.606214)
		(width 0.18288)
		(layer "In11.Cu")
		(net "M_D_CPU0_SA_DQS_DN<2>")
	)
	(segment
		(start 271.389094 -293.90975)
		(end 270.840454 -293.90975)
		(width 0.18288)
		(layer "In11.Cu")
		(net "M_D_CPU0_SA_DQS_DN<2>")
	)
	(segment
		(start 346.063062 -272.639282)
		(end 346.031312 -272.755106)
		(width 0.088646)
		(layer "In11.Cu")
		(net "M_D_CPU0_SA_DQS_DN<2>")
	)
	(segment
		(start 297.407838 -295.959784)
		(end 297.04792 -296.319448)
		(width 0.18288)
		(layer "In11.Cu")
		(net "M_D_CPU0_SA_DQS_DN<2>")
	)
	(segment
		(start 301.836582 -294.619172)
		(end 301.333154 -294.955722)
		(width 0.18288)
		(layer "In11.Cu")
		(net "M_D_CPU0_SA_DQS_DN<2>")
	)
	(segment
		(start 336.862928 -272.957544)
		(end 336.852514 -272.96364)
		(width 0.088646)
		(layer "In11.Cu")
		(net "M_D_CPU0_SA_DQS_DN<2>")
	)
	(segment
		(start 286.300672 -295.646094)
		(end 285.752032 -295.646094)
		(width 0.18288)
		(layer "In11.Cu")
		(net "M_D_CPU0_SA_DQS_DN<2>")
	)
	(segment
		(start 301.333154 -294.955722)
		(end 300.900592 -295.38803)
		(width 0.18288)
		(layer "In11.Cu")
		(net "M_D_CPU0_SA_DQS_DN<2>")
	)
	(segment
		(start 299.215302 -295.4909)
		(end 298.804838 -295.4909)
		(width 0.18288)
		(layer "In11.Cu")
		(net "M_D_CPU0_SA_DQS_DN<2>")
	)
	(segment
		(start 274.380452 -294.993568)
		(end 273.306286 -294.549068)
		(width 0.18288)
		(layer "In11.Cu")
		(net "M_D_CPU0_SA_DQS_DN<2>")
	)
	(segment
		(start 268.611858 -293.791132)
		(end 268.337284 -294.065706)
		(width 0.18288)
		(layer "In11.Cu")
		(net "M_D_CPU0_SA_DQS_DN<2>")
	)
	(segment
		(start 340.237064 -272.96364)
		(end 340.222332 -272.955004)
		(width 0.088646)
		(layer "In11.Cu")
		(net "M_D_CPU0_SA_DQS_DN<2>")
	)
	(segment
		(start 280.332942 -296.586402)
		(end 280.087578 -296.341038)
		(width 0.18288)
		(layer "In11.Cu")
		(net "M_D_CPU0_SA_DQS_DN<2>")
	)
	(segment
		(start 339.297264 -272.96364)
		(end 339.28685 -272.957544)
		(width 0.088646)
		(layer "In11.Cu")
		(net "M_D_CPU0_SA_DQS_DN<2>")
	)
	(segment
		(start 334.598518 -272.96364)
		(end 334.588104 -272.957544)
		(width 0.088646)
		(layer "In11.Cu")
		(net "M_D_CPU0_SA_DQS_DN<2>")
	)
	(segment
		(start 283.44495 -295.772332)
		(end 283.221176 -295.772332)
		(width 0.18288)
		(layer "In11.Cu")
		(net "M_D_CPU0_SA_DQS_DN<2>")
	)
	(segment
		(start 284.383988 -295.770554)
		(end 284.105858 -295.492424)
		(width 0.18288)
		(layer "In11.Cu")
		(net "M_D_CPU0_SA_DQS_DN<2>")
	)
	(segment
		(start 266.744958 -293.389304)
		(end 265.932158 -293.389304)
		(width 0.18288)
		(layer "In11.Cu")
		(net "M_D_CPU0_SA_DQS_DN<2>")
	)
	(segment
		(start 297.884342 -295.762172)
		(end 297.407838 -295.959784)
		(width 0.18288)
		(layer "In11.Cu")
		(net "M_D_CPU0_SA_DQS_DN<2>")
	)
	(segment
		(start 345.837764 -272.818098)
		(end 345.564206 -272.818098)
		(width 0.088646)
		(layer "In11.Cu")
		(net "M_D_CPU0_SA_DQS_DN<2>")
	)
	(segment
		(start 312.496962 -290.410646)
		(end 311.707784 -290.737036)
		(width 0.18288)
		(layer "In11.Cu")
		(net "M_D_CPU0_SA_DQS_DN<2>")
	)
	(segment
		(start 314.353448 -290.410646)
		(end 312.496962 -290.410646)
		(width 0.18288)
		(layer "In11.Cu")
		(net "M_D_CPU0_SA_DQS_DN<2>")
	)
	(segment
		(start 328.653648 -275.613368)
		(end 314.634372 -289.632644)
		(width 0.18288)
		(layer "In11.Cu")
		(net "M_D_CPU0_SA_DQS_DN<2>")
	)
	(segment
		(start 335.922874 -272.957544)
		(end 335.91246 -272.96364)
		(width 0.088646)
		(layer "In11.Cu")
		(net "M_D_CPU0_SA_DQS_DN<2>")
	)
	(segment
		(start 300.900592 -295.38803)
		(end 300.014132 -295.755314)
		(width 0.18288)
		(layer "In11.Cu")
		(net "M_D_CPU0_SA_DQS_DN<2>")
	)
	(segment
		(start 270.840454 -293.90975)
		(end 270.715994 -294.03421)
		(width 0.18288)
		(layer "In11.Cu")
		(net "M_D_CPU0_SA_DQS_DN<2>")
	)
	(segment
		(start 293.711376 -296.277792)
		(end 292.843204 -295.91762)
		(width 0.18288)
		(layer "In11.Cu")
		(net "M_D_CPU0_SA_DQS_DN<2>")
	)
	(segment
		(start 295.095422 -296.341038)
		(end 294.708834 -296.341038)
		(width 0.18288)
		(layer "In11.Cu")
		(net "M_D_CPU0_SA_DQS_DN<2>")
	)
	(segment
		(start 277.329392 -297.200574)
		(end 276.648926 -296.918888)
		(width 0.18288)
		(layer "In11.Cu")
		(net "M_D_CPU0_SA_DQS_DN<2>")
	)
	(segment
		(start 288.128202 -295.036748)
		(end 287.651952 -295.512744)
		(width 0.18288)
		(layer "In11.Cu")
		(net "M_D_CPU0_SA_DQS_DN<2>")
	)
	(segment
		(start 341.176864 -272.96364)
		(end 341.162132 -272.955004)
		(width 0.088646)
		(layer "In11.Cu")
		(net "M_D_CPU0_SA_DQS_DN<2>")
	)
	(segment
		(start 311.545224 -290.669726)
		(end 311.037986 -290.87953)
		(width 0.18288)
		(layer "In11.Cu")
		(net "M_D_CPU0_SA_DQS_DN<2>")
	)
	(segment
		(start 290.694618 -295.812718)
		(end 290.306506 -295.424606)
		(width 0.18288)
		(layer "In11.Cu")
		(net "M_D_CPU0_SA_DQS_DN<2>")
	)
	(segment
		(start 306.386484 -292.367462)
		(end 306.223924 -292.300152)
		(width 0.18288)
		(layer "In11.Cu")
		(net "M_D_CPU0_SA_DQS_DN<2>")
	)
	(segment
		(start 346.031312 -272.755106)
		(end 345.99245 -272.777204)
		(width 0.088646)
		(layer "In11.Cu")
		(net "M_D_CPU0_SA_DQS_DN<2>")
	)
	(segment
		(start 294.426386 -296.623486)
		(end 294.05707 -296.623486)
		(width 0.18288)
		(layer "In11.Cu")
		(net "M_D_CPU0_SA_DQS_DN<2>")
	)
	(segment
		(start 289.742626 -295.036748)
		(end 288.128202 -295.036748)
		(width 0.18288)
		(layer "In11.Cu")
		(net "M_D_CPU0_SA_DQS_DN<2>")
	)
	(arc
		(start 343.981532 -272.955004)
		(mid 343.705057 -272.887684)
		(end 343.43086 -272.96364)
		(width 0.088646)
		(layer "In11.Cu")
		(net "M_D_CPU0_SA_DQS_DN<2>")
	)
	(arc
		(start 342.49106 -272.96364)
		(mid 342.303862 -273.013783)
		(end 342.116664 -272.96364)
		(width 0.088646)
		(layer "In11.Cu")
		(net "M_D_CPU0_SA_DQS_DN<2>")
	)
	(arc
		(start 341.162132 -272.955004)
		(mid 340.885657 -272.887684)
		(end 340.61146 -272.96364)
		(width 0.088646)
		(layer "In11.Cu")
		(net "M_D_CPU0_SA_DQS_DN<2>")
	)
	(arc
		(start 339.28685 -272.957544)
		(mid 339.008672 -272.887821)
		(end 338.732114 -272.96364)
		(width 0.088646)
		(layer "In11.Cu")
		(net "M_D_CPU0_SA_DQS_DN<2>")
	)
	(arc
		(start 339.67166 -272.96364)
		(mid 339.484462 -273.013783)
		(end 339.297264 -272.96364)
		(width 0.088646)
		(layer "In11.Cu")
		(net "M_D_CPU0_SA_DQS_DN<2>")
	)
	(arc
		(start 344.37066 -272.96364)
		(mid 344.183462 -273.013783)
		(end 343.996264 -272.96364)
		(width 0.088646)
		(layer "In11.Cu")
		(net "M_D_CPU0_SA_DQS_DN<2>")
	)
	(arc
		(start 334.03286 -272.96364)
		(mid 333.845662 -273.013783)
		(end 333.658464 -272.96364)
		(width 0.088646)
		(layer "In11.Cu")
		(net "M_D_CPU0_SA_DQS_DN<2>")
	)
	(arc
		(start 337.417664 -272.96364)
		(mid 337.141105 -272.887897)
		(end 336.862928 -272.957544)
		(width 0.088646)
		(layer "In11.Cu")
		(net "M_D_CPU0_SA_DQS_DN<2>")
	)
	(arc
		(start 343.056464 -272.96364)
		(mid 342.773762 -272.887864)
		(end 342.49106 -272.96364)
		(width 0.088646)
		(layer "In11.Cu")
		(net "M_D_CPU0_SA_DQS_DN<2>")
	)
	(arc
		(start 345.310714 -272.96364)
		(mid 345.123516 -273.013783)
		(end 344.936318 -272.96364)
		(width 0.088646)
		(layer "In11.Cu")
		(net "M_D_CPU0_SA_DQS_DN<2>")
	)
	(arc
		(start 343.43086 -272.96364)
		(mid 343.243662 -273.013783)
		(end 343.056464 -272.96364)
		(width 0.088646)
		(layer "In11.Cu")
		(net "M_D_CPU0_SA_DQS_DN<2>")
	)
	(arc
		(start 336.478118 -272.96364)
		(mid 336.201305 -272.88777)
		(end 335.922874 -272.957544)
		(width 0.088646)
		(layer "In11.Cu")
		(net "M_D_CPU0_SA_DQS_DN<2>")
	)
	(arc
		(start 337.79206 -272.96364)
		(mid 337.604862 -273.013783)
		(end 337.417664 -272.96364)
		(width 0.088646)
		(layer "In11.Cu")
		(net "M_D_CPU0_SA_DQS_DN<2>")
	)
	(arc
		(start 340.61146 -272.96364)
		(mid 340.424262 -273.013783)
		(end 340.237064 -272.96364)
		(width 0.088646)
		(layer "In11.Cu")
		(net "M_D_CPU0_SA_DQS_DN<2>")
	)
	(arc
		(start 333.009748 -273.022314)
		(mid 332.992803 -273.037218)
		(end 332.976474 -273.052794)
		(width 0.088646)
		(layer "In11.Cu")
		(net "M_D_CPU0_SA_DQS_DN<2>")
	)
	(arc
		(start 335.91246 -272.96364)
		(mid 335.725262 -273.013783)
		(end 335.538064 -272.96364)
		(width 0.088646)
		(layer "In11.Cu")
		(net "M_D_CPU0_SA_DQS_DN<2>")
	)
	(arc
		(start 335.538064 -272.96364)
		(mid 335.261505 -272.887897)
		(end 334.983328 -272.957544)
		(width 0.088646)
		(layer "In11.Cu")
		(net "M_D_CPU0_SA_DQS_DN<2>")
	)
	(arc
		(start 338.357718 -272.96364)
		(mid 338.080905 -272.88777)
		(end 337.802474 -272.957544)
		(width 0.088646)
		(layer "In11.Cu")
		(net "M_D_CPU0_SA_DQS_DN<2>")
	)
	(arc
		(start 340.222332 -272.955004)
		(mid 339.945857 -272.887684)
		(end 339.67166 -272.96364)
		(width 0.088646)
		(layer "In11.Cu")
		(net "M_D_CPU0_SA_DQS_DN<2>")
	)
	(arc
		(start 334.972914 -272.96364)
		(mid 334.785716 -273.013783)
		(end 334.598518 -272.96364)
		(width 0.088646)
		(layer "In11.Cu")
		(net "M_D_CPU0_SA_DQS_DN<2>")
	)
	(arc
		(start 345.99245 -272.777204)
		(mid 345.917765 -272.807709)
		(end 345.837764 -272.818098)
		(width 0.088646)
		(layer "In11.Cu")
		(net "M_D_CPU0_SA_DQS_DN<2>")
	)
	(arc
		(start 338.732114 -272.96364)
		(mid 338.544916 -273.013783)
		(end 338.357718 -272.96364)
		(width 0.088646)
		(layer "In11.Cu")
		(net "M_D_CPU0_SA_DQS_DN<2>")
	)
	(arc
		(start 336.852514 -272.96364)
		(mid 336.665316 -273.013783)
		(end 336.478118 -272.96364)
		(width 0.088646)
		(layer "In11.Cu")
		(net "M_D_CPU0_SA_DQS_DN<2>")
	)
	(arc
		(start 333.093314 -272.96364)
		(mid 333.050198 -272.991079)
		(end 333.009748 -273.022314)
		(width 0.088646)
		(layer "In11.Cu")
		(net "M_D_CPU0_SA_DQS_DN<2>")
	)
	(arc
		(start 341.55126 -272.96364)
		(mid 341.364062 -273.013783)
		(end 341.176864 -272.96364)
		(width 0.088646)
		(layer "In11.Cu")
		(net "M_D_CPU0_SA_DQS_DN<2>")
	)
	(arc
		(start 333.64805 -272.957544)
		(mid 333.369872 -272.887821)
		(end 333.093314 -272.96364)
		(width 0.088646)
		(layer "In11.Cu")
		(net "M_D_CPU0_SA_DQS_DN<2>")
	)
	(arc
		(start 344.925904 -272.957544)
		(mid 344.647472 -272.887698)
		(end 344.37066 -272.96364)
		(width 0.088646)
		(layer "In11.Cu")
		(net "M_D_CPU0_SA_DQS_DN<2>")
	)
	(arc
		(start 342.101932 -272.955004)
		(mid 341.825457 -272.887684)
		(end 341.55126 -272.96364)
		(width 0.088646)
		(layer "In11.Cu")
		(net "M_D_CPU0_SA_DQS_DN<2>")
	)
	(arc
		(start 334.588104 -272.957544)
		(mid 334.309672 -272.887698)
		(end 334.03286 -272.96364)
		(width 0.088646)
		(layer "In11.Cu")
		(net "M_D_CPU0_SA_DQS_DN<2>")
	)
	(segment
		(start 261.984744 -303.403)
		(end 261.798054 -303.403)
		(width 0.20066)
		(layer "F.Cu")
		(net "M_D_CPU0_SA_DQS_DN<1>")
	)
	(segment
		(start 257.404108 -302.977804)
		(end 256.890266 -302.977804)
		(width 0.20066)
		(layer "F.Cu")
		(net "M_D_CPU0_SA_DQS_DN<1>")
	)
	(segment
		(start 263.624314 -302.716692)
		(end 263.077706 -302.716692)
		(width 0.20066)
		(layer "F.Cu")
		(net "M_D_CPU0_SA_DQS_DN<1>")
	)
	(segment
		(start 262.816594 -302.977804)
		(end 262.40994 -302.977804)
		(width 0.20066)
		(layer "F.Cu")
		(net "M_D_CPU0_SA_DQS_DN<1>")
	)
	(segment
		(start 261.381494 -303.141634)
		(end 259.067808 -303.141634)
		(width 0.1016)
		(layer "F.Cu")
		(net "M_D_CPU0_SA_DQS_DN<1>")
	)
	(segment
		(start 261.798054 -303.403)
		(end 261.536688 -303.141634)
		(width 0.20066)
		(layer "F.Cu")
		(net "M_D_CPU0_SA_DQS_DN<1>")
	)
	(segment
		(start 261.536688 -303.141634)
		(end 261.381494 -303.141634)
		(width 0.20066)
		(layer "F.Cu")
		(net "M_D_CPU0_SA_DQS_DN<1>")
	)
	(segment
		(start 256.629154 -302.716692)
		(end 256.080514 -302.716692)
		(width 0.20066)
		(layer "F.Cu")
		(net "M_D_CPU0_SA_DQS_DN<1>")
	)
	(segment
		(start 258.852162 -303.130966)
		(end 258.580128 -303.403)
		(width 0.20066)
		(layer "F.Cu")
		(net "M_D_CPU0_SA_DQS_DN<1>")
	)
	(segment
		(start 262.40994 -302.977804)
		(end 261.984744 -303.403)
		(width 0.20066)
		(layer "F.Cu")
		(net "M_D_CPU0_SA_DQS_DN<1>")
	)
	(segment
		(start 259.067808 -303.141634)
		(end 259.05714 -303.130966)
		(width 0.101854)
		(layer "F.Cu")
		(net "M_D_CPU0_SA_DQS_DN<1>")
	)
	(segment
		(start 258.040124 -303.403)
		(end 257.404108 -302.977804)
		(width 0.20066)
		(layer "F.Cu")
		(net "M_D_CPU0_SA_DQS_DN<1>")
	)
	(segment
		(start 264.729214 -302.716692)
		(end 263.624314 -302.716692)
		(width 0.20066)
		(layer "F.Cu")
		(net "M_D_CPU0_SA_DQS_DN<1>")
	)
	(segment
		(start 259.05714 -303.130966)
		(end 259.056378 -303.130966)
		(width 0.101854)
		(layer "F.Cu")
		(net "M_D_CPU0_SA_DQS_DN<1>")
	)
	(segment
		(start 263.077706 -302.716692)
		(end 262.816594 -302.977804)
		(width 0.20066)
		(layer "F.Cu")
		(net "M_D_CPU0_SA_DQS_DN<1>")
	)
	(segment
		(start 256.890266 -302.977804)
		(end 256.629154 -302.716692)
		(width 0.20066)
		(layer "F.Cu")
		(net "M_D_CPU0_SA_DQS_DN<1>")
	)
	(segment
		(start 258.580128 -303.403)
		(end 258.040124 -303.403)
		(width 0.20066)
		(layer "F.Cu")
		(net "M_D_CPU0_SA_DQS_DN<1>")
	)
	(segment
		(start 259.056378 -303.130966)
		(end 258.852162 -303.130966)
		(width 0.20066)
		(layer "F.Cu")
		(net "M_D_CPU0_SA_DQS_DN<1>")
	)
	(arc
		(start 346.063316 -276.986492)
		(mid 346.063252 -277.254462)
		(end 346.063062 -277.522432)
		(width 0.20066)
		(layer "F.Cu")
		(net "M_D_CPU0_SA_DQS_DN<1>")
	)
	(segment
		(start 274.820634 -306.455572)
		(end 274.337526 -305.971702)
		(width 0.18288)
		(layer "In11.Cu")
		(net "M_D_CPU0_SA_DQS_DN<1>")
	)
	(segment
		(start 297.914568 -308.722776)
		(end 297.752008 -308.655466)
		(width 0.18288)
		(layer "In11.Cu")
		(net "M_D_CPU0_SA_DQS_DN<1>")
	)
	(segment
		(start 299.198538 -308.240938)
		(end 298.811442 -308.240938)
		(width 0.18288)
		(layer "In11.Cu")
		(net "M_D_CPU0_SA_DQS_DN<1>")
	)
	(segment
		(start 313.099958 -300.849792)
		(end 312.716926 -301.23257)
		(width 0.18288)
		(layer "In11.Cu")
		(net "M_D_CPU0_SA_DQS_DN<1>")
	)
	(segment
		(start 320.733928 -292.80739)
		(end 317.041784 -296.499534)
		(width 0.18288)
		(layer "In11.Cu")
		(net "M_D_CPU0_SA_DQS_DN<1>")
	)
	(segment
		(start 286.31134 -308.517544)
		(end 285.7627 -308.517544)
		(width 0.18288)
		(layer "In11.Cu")
		(net "M_D_CPU0_SA_DQS_DN<1>")
	)
	(segment
		(start 267.488416 -303.69764)
		(end 266.738354 -304.008536)
		(width 0.18288)
		(layer "In11.Cu")
		(net "M_D_CPU0_SA_DQS_DN<1>")
	)
	(segment
		(start 344.936064 -277.84679)
		(end 344.921332 -277.838154)
		(width 0.088646)
		(layer "In11.Cu")
		(net "M_D_CPU0_SA_DQS_DN<1>")
	)
	(segment
		(start 284.393132 -308.517544)
		(end 284.116526 -308.240938)
		(width 0.18288)
		(layer "In11.Cu")
		(net "M_D_CPU0_SA_DQS_DN<1>")
	)
	(segment
		(start 269.804642 -303.40046)
		(end 269.282926 -303.40046)
		(width 0.18288)
		(layer "In11.Cu")
		(net "M_D_CPU0_SA_DQS_DN<1>")
	)
	(segment
		(start 290.703 -309.202836)
		(end 290.57854 -309.078376)
		(width 0.18288)
		(layer "In11.Cu")
		(net "M_D_CPU0_SA_DQS_DN<1>")
	)
	(segment
		(start 345.310968 -277.847044)
		(end 345.310714 -277.84679)
		(width 0.088646)
		(layer "In11.Cu")
		(net "M_D_CPU0_SA_DQS_DN<1>")
	)
	(segment
		(start 346.063062 -277.522432)
		(end 346.031312 -277.638256)
		(width 0.088646)
		(layer "In11.Cu")
		(net "M_D_CPU0_SA_DQS_DN<1>")
	)
	(segment
		(start 285.63824 -308.393084)
		(end 285.0896 -308.393084)
		(width 0.18288)
		(layer "In11.Cu")
		(net "M_D_CPU0_SA_DQS_DN<1>")
	)
	(segment
		(start 305.747928 -303.219358)
		(end 305.748182 -303.219612)
		(width 0.18288)
		(layer "In11.Cu")
		(net "M_D_CPU0_SA_DQS_DN<1>")
	)
	(segment
		(start 332.861666 -280.069544)
		(end 332.861666 -280.875232)
		(width 0.088646)
		(layer "In11.Cu")
		(net "M_D_CPU0_SA_DQS_DN<1>")
	)
	(segment
		(start 305.748182 -303.219612)
		(end 305.49215 -303.837848)
		(width 0.18288)
		(layer "In11.Cu")
		(net "M_D_CPU0_SA_DQS_DN<1>")
	)
	(segment
		(start 298.421298 -308.512972)
		(end 297.914568 -308.722776)
		(width 0.18288)
		(layer "In11.Cu")
		(net "M_D_CPU0_SA_DQS_DN<1>")
	)
	(segment
		(start 278.254714 -309.813706)
		(end 277.923752 -309.950866)
		(width 0.18288)
		(layer "In11.Cu")
		(net "M_D_CPU0_SA_DQS_DN<1>")
	)
	(segment
		(start 316.449202 -299.172122)
		(end 316.06109 -299.560234)
		(width 0.18288)
		(layer "In11.Cu")
		(net "M_D_CPU0_SA_DQS_DN<1>")
	)
	(segment
		(start 300.170596 -308.521608)
		(end 299.479208 -308.521608)
		(width 0.18288)
		(layer "In11.Cu")
		(net "M_D_CPU0_SA_DQS_DN<1>")
	)
	(segment
		(start 280.274268 -309.367682)
		(end 279.997662 -309.091076)
		(width 0.18288)
		(layer "In11.Cu")
		(net "M_D_CPU0_SA_DQS_DN<1>")
	)
	(segment
		(start 279.62225 -309.091076)
		(end 279.342596 -309.37073)
		(width 0.18288)
		(layer "In11.Cu")
		(net "M_D_CPU0_SA_DQS_DN<1>")
	)
	(segment
		(start 268.377162 -303.374552)
		(end 267.811758 -303.374552)
		(width 0.18288)
		(layer "In11.Cu")
		(net "M_D_CPU0_SA_DQS_DN<1>")
	)
	(segment
		(start 286.4358 -308.393084)
		(end 286.31134 -308.517544)
		(width 0.18288)
		(layer "In11.Cu")
		(net "M_D_CPU0_SA_DQS_DN<1>")
	)
	(segment
		(start 269.02537 -303.142904)
		(end 268.60881 -303.142904)
		(width 0.18288)
		(layer "In11.Cu")
		(net "M_D_CPU0_SA_DQS_DN<1>")
	)
	(segment
		(start 297.752008 -308.655466)
		(end 297.24477 -308.86527)
		(width 0.18288)
		(layer "In11.Cu")
		(net "M_D_CPU0_SA_DQS_DN<1>")
	)
	(segment
		(start 289.311842 -309.202836)
		(end 287.65754 -308.517544)
		(width 0.18288)
		(layer "In11.Cu")
		(net "M_D_CPU0_SA_DQS_DN<1>")
	)
	(segment
		(start 285.7627 -308.517544)
		(end 285.63824 -308.393084)
		(width 0.18288)
		(layer "In11.Cu")
		(net "M_D_CPU0_SA_DQS_DN<1>")
	)
	(segment
		(start 270.062706 -303.478692)
		(end 269.804642 -303.40046)
		(width 0.18288)
		(layer "In11.Cu")
		(net "M_D_CPU0_SA_DQS_DN<1>")
	)
	(segment
		(start 297.24477 -308.86527)
		(end 297.17746 -309.028084)
		(width 0.18288)
		(layer "In11.Cu")
		(net "M_D_CPU0_SA_DQS_DN<1>")
	)
	(segment
		(start 314.584334 -300.832012)
		(end 314.34405 -300.591728)
		(width 0.18288)
		(layer "In11.Cu")
		(net "M_D_CPU0_SA_DQS_DN<1>")
	)
	(segment
		(start 294.70477 -309.091076)
		(end 294.407336 -309.38851)
		(width 0.18288)
		(layer "In11.Cu")
		(net "M_D_CPU0_SA_DQS_DN<1>")
	)
	(segment
		(start 283.264864 -308.492652)
		(end 281.152092 -309.367682)
		(width 0.18288)
		(layer "In11.Cu")
		(net "M_D_CPU0_SA_DQS_DN<1>")
	)
	(segment
		(start 305.329082 -303.905158)
		(end 305.119024 -304.412142)
		(width 0.18288)
		(layer "In11.Cu")
		(net "M_D_CPU0_SA_DQS_DN<1>")
	)
	(segment
		(start 309.498492 -301.753524)
		(end 308.666388 -301.753524)
		(width 0.18288)
		(layer "In11.Cu")
		(net "M_D_CPU0_SA_DQS_DN<1>")
	)
	(segment
		(start 284.116526 -308.240938)
		(end 283.723334 -308.240938)
		(width 0.18288)
		(layer "In11.Cu")
		(net "M_D_CPU0_SA_DQS_DN<1>")
	)
	(segment
		(start 298.539408 -308.512972)
		(end 298.421298 -308.512972)
		(width 0.18288)
		(layer "In11.Cu")
		(net "M_D_CPU0_SA_DQS_DN<1>")
	)
	(segment
		(start 277.923752 -309.950866)
		(end 277.47976 -309.950866)
		(width 0.18288)
		(layer "In11.Cu")
		(net "M_D_CPU0_SA_DQS_DN<1>")
	)
	(segment
		(start 273.644614 -305.549554)
		(end 273.137376 -305.339496)
		(width 0.18288)
		(layer "In11.Cu")
		(net "M_D_CPU0_SA_DQS_DN<1>")
	)
	(segment
		(start 286.98444 -308.393084)
		(end 286.4358 -308.393084)
		(width 0.18288)
		(layer "In11.Cu")
		(net "M_D_CPU0_SA_DQS_DN<1>")
	)
	(segment
		(start 299.479208 -308.521608)
		(end 299.198538 -308.240938)
		(width 0.18288)
		(layer "In11.Cu")
		(net "M_D_CPU0_SA_DQS_DN<1>")
	)
	(segment
		(start 317.041784 -296.499534)
		(end 317.041784 -298.755562)
		(width 0.18288)
		(layer "In11.Cu")
		(net "M_D_CPU0_SA_DQS_DN<1>")
	)
	(segment
		(start 332.861666 -280.875232)
		(end 332.160372 -281.576526)
		(width 0.088646)
		(layer "In11.Cu")
		(net "M_D_CPU0_SA_DQS_DN<1>")
	)
	(segment
		(start 291.716968 -309.202836)
		(end 290.703 -309.202836)
		(width 0.18288)
		(layer "In11.Cu")
		(net "M_D_CPU0_SA_DQS_DN<1>")
	)
	(segment
		(start 271.616678 -304.367438)
		(end 271.16024 -304.062384)
		(width 0.18288)
		(layer "In11.Cu")
		(net "M_D_CPU0_SA_DQS_DN<1>")
	)
	(segment
		(start 330.801472 -282.024582)
		(end 320.733928 -292.092126)
		(width 0.18288)
		(layer "In11.Cu")
		(net "M_D_CPU0_SA_DQS_DN<1>")
	)
	(segment
		(start 293.788338 -309.101236)
		(end 292.995096 -308.772814)
		(width 0.18288)
		(layer "In11.Cu")
		(net "M_D_CPU0_SA_DQS_DN<1>")
	)
	(segment
		(start 292.995096 -308.772814)
		(end 292.421056 -308.772814)
		(width 0.18288)
		(layer "In11.Cu")
		(net "M_D_CPU0_SA_DQS_DN<1>")
	)
	(segment
		(start 298.811442 -308.240938)
		(end 298.539408 -308.512972)
		(width 0.18288)
		(layer "In11.Cu")
		(net "M_D_CPU0_SA_DQS_DN<1>")
	)
	(segment
		(start 313.611514 -300.849792)
		(end 313.099958 -300.849792)
		(width 0.18288)
		(layer "In11.Cu")
		(net "M_D_CPU0_SA_DQS_DN<1>")
	)
	(segment
		(start 268.60881 -303.142904)
		(end 268.377162 -303.374552)
		(width 0.18288)
		(layer "In11.Cu")
		(net "M_D_CPU0_SA_DQS_DN<1>")
	)
	(segment
		(start 295.386252 -309.363618)
		(end 295.11371 -309.091076)
		(width 0.18288)
		(layer "In11.Cu")
		(net "M_D_CPU0_SA_DQS_DN<1>")
	)
	(segment
		(start 314.965334 -300.832012)
		(end 314.584334 -300.832012)
		(width 0.18288)
		(layer "In11.Cu")
		(net "M_D_CPU0_SA_DQS_DN<1>")
	)
	(segment
		(start 266.525502 -304.008536)
		(end 266.36599 -303.942242)
		(width 0.18288)
		(layer "In11.Cu")
		(net "M_D_CPU0_SA_DQS_DN<1>")
	)
	(segment
		(start 309.811166 -301.44085)
		(end 309.498492 -301.753524)
		(width 0.18288)
		(layer "In11.Cu")
		(net "M_D_CPU0_SA_DQS_DN<1>")
	)
	(segment
		(start 316.06109 -299.560234)
		(end 316.06109 -299.736256)
		(width 0.18288)
		(layer "In11.Cu")
		(net "M_D_CPU0_SA_DQS_DN<1>")
	)
	(segment
		(start 302.814736 -306.716938)
		(end 301.381922 -307.310282)
		(width 0.18288)
		(layer "In11.Cu")
		(net "M_D_CPU0_SA_DQS_DN<1>")
	)
	(segment
		(start 267.811758 -303.374552)
		(end 267.488416 -303.69764)
		(width 0.18288)
		(layer "In11.Cu")
		(net "M_D_CPU0_SA_DQS_DN<1>")
	)
	(segment
		(start 297.17746 -309.028084)
		(end 296.366946 -309.363618)
		(width 0.18288)
		(layer "In11.Cu")
		(net "M_D_CPU0_SA_DQS_DN<1>")
	)
	(segment
		(start 311.528714 -301.724822)
		(end 310.54675 -301.724822)
		(width 0.18288)
		(layer "In11.Cu")
		(net "M_D_CPU0_SA_DQS_DN<1>")
	)
	(segment
		(start 287.65754 -308.517544)
		(end 287.1089 -308.517544)
		(width 0.18288)
		(layer "In11.Cu")
		(net "M_D_CPU0_SA_DQS_DN<1>")
	)
	(segment
		(start 307.158136 -302.72736)
		(end 306.239926 -302.72736)
		(width 0.18288)
		(layer "In11.Cu")
		(net "M_D_CPU0_SA_DQS_DN<1>")
	)
	(segment
		(start 316.06109 -299.736256)
		(end 314.965334 -300.832012)
		(width 0.18288)
		(layer "In11.Cu")
		(net "M_D_CPU0_SA_DQS_DN<1>")
	)
	(segment
		(start 274.98548 -307.38445)
		(end 274.98548 -306.852828)
		(width 0.18288)
		(layer "In11.Cu")
		(net "M_D_CPU0_SA_DQS_DN<1>")
	)
	(segment
		(start 301.381922 -307.310028)
		(end 300.170596 -308.521608)
		(width 0.18288)
		(layer "In11.Cu")
		(net "M_D_CPU0_SA_DQS_DN<1>")
	)
	(segment
		(start 273.137376 -305.339496)
		(end 272.974816 -305.406806)
		(width 0.18288)
		(layer "In11.Cu")
		(net "M_D_CPU0_SA_DQS_DN<1>")
	)
	(segment
		(start 277.47976 -309.950866)
		(end 276.38883 -309.499)
		(width 0.18288)
		(layer "In11.Cu")
		(net "M_D_CPU0_SA_DQS_DN<1>")
	)
	(segment
		(start 314.34405 -300.591728)
		(end 313.869578 -300.591728)
		(width 0.18288)
		(layer "In11.Cu")
		(net "M_D_CPU0_SA_DQS_DN<1>")
	)
	(segment
		(start 305.186588 -304.574702)
		(end 304.833528 -305.426618)
		(width 0.18288)
		(layer "In11.Cu")
		(net "M_D_CPU0_SA_DQS_DN<1>")
	)
	(segment
		(start 345.837764 -277.701248)
		(end 345.564206 -277.701248)
		(width 0.088646)
		(layer "In11.Cu")
		(net "M_D_CPU0_SA_DQS_DN<1>")
	)
	(segment
		(start 336.860896 -277.84171)
		(end 336.852006 -277.847044)
		(width 0.088646)
		(layer "In11.Cu")
		(net "M_D_CPU0_SA_DQS_DN<1>")
	)
	(segment
		(start 337.802474 -277.840694)
		(end 337.79206 -277.84679)
		(width 0.088646)
		(layer "In11.Cu")
		(net "M_D_CPU0_SA_DQS_DN<1>")
	)
	(segment
		(start 269.282926 -303.40046)
		(end 269.02537 -303.142904)
		(width 0.18288)
		(layer "In11.Cu")
		(net "M_D_CPU0_SA_DQS_DN<1>")
	)
	(segment
		(start 287.1089 -308.517544)
		(end 286.98444 -308.393084)
		(width 0.18288)
		(layer "In11.Cu")
		(net "M_D_CPU0_SA_DQS_DN<1>")
	)
	(segment
		(start 302.882046 -306.554124)
		(end 302.814736 -306.716938)
		(width 0.18288)
		(layer "In11.Cu")
		(net "M_D_CPU0_SA_DQS_DN<1>")
	)
	(segment
		(start 335.630012 -278.321008)
		(end 335.630012 -278.336502)
		(width 0.088646)
		(layer "In11.Cu")
		(net "M_D_CPU0_SA_DQS_DN<1>")
	)
	(segment
		(start 335.45145 -278.65578)
		(end 335.44256 -278.66086)
		(width 0.088646)
		(layer "In11.Cu")
		(net "M_D_CPU0_SA_DQS_DN<1>")
	)
	(segment
		(start 334.099154 -278.832056)
		(end 332.861666 -280.069544)
		(width 0.088646)
		(layer "In11.Cu")
		(net "M_D_CPU0_SA_DQS_DN<1>")
	)
	(segment
		(start 317.041784 -298.755562)
		(end 316.625224 -299.172122)
		(width 0.18288)
		(layer "In11.Cu")
		(net "M_D_CPU0_SA_DQS_DN<1>")
	)
	(segment
		(start 289.90544 -309.202836)
		(end 289.311842 -309.202836)
		(width 0.18288)
		(layer "In11.Cu")
		(net "M_D_CPU0_SA_DQS_DN<1>")
	)
	(segment
		(start 274.98548 -306.852828)
		(end 274.820634 -306.455572)
		(width 0.18288)
		(layer "In11.Cu")
		(net "M_D_CPU0_SA_DQS_DN<1>")
	)
	(segment
		(start 295.11371 -309.091076)
		(end 294.70477 -309.091076)
		(width 0.18288)
		(layer "In11.Cu")
		(net "M_D_CPU0_SA_DQS_DN<1>")
	)
	(segment
		(start 343.996264 -277.84679)
		(end 343.981532 -277.838154)
		(width 0.088646)
		(layer "In11.Cu")
		(net "M_D_CPU0_SA_DQS_DN<1>")
	)
	(segment
		(start 266.36599 -303.942242)
		(end 265.400028 -302.97628)
		(width 0.18288)
		(layer "In11.Cu")
		(net "M_D_CPU0_SA_DQS_DN<1>")
	)
	(segment
		(start 270.98752 -304.096674)
		(end 270.062706 -303.478692)
		(width 0.18288)
		(layer "In11.Cu")
		(net "M_D_CPU0_SA_DQS_DN<1>")
	)
	(segment
		(start 284.96514 -308.517544)
		(end 284.393132 -308.517544)
		(width 0.18288)
		(layer "In11.Cu")
		(net "M_D_CPU0_SA_DQS_DN<1>")
	)
	(segment
		(start 294.407336 -309.38851)
		(end 294.075866 -309.38851)
		(width 0.18288)
		(layer "In11.Cu")
		(net "M_D_CPU0_SA_DQS_DN<1>")
	)
	(segment
		(start 312.716926 -301.23257)
		(end 311.528714 -301.724822)
		(width 0.18288)
		(layer "In11.Cu")
		(net "M_D_CPU0_SA_DQS_DN<1>")
	)
	(segment
		(start 303.389284 -306.344066)
		(end 302.882046 -306.554124)
		(width 0.18288)
		(layer "In11.Cu")
		(net "M_D_CPU0_SA_DQS_DN<1>")
	)
	(segment
		(start 308.666388 -301.753524)
		(end 308.070758 -302.349154)
		(width 0.18288)
		(layer "In11.Cu")
		(net "M_D_CPU0_SA_DQS_DN<1>")
	)
	(segment
		(start 336.47761 -277.847044)
		(end 336.462878 -277.838408)
		(width 0.088646)
		(layer "In11.Cu")
		(net "M_D_CPU0_SA_DQS_DN<1>")
	)
	(segment
		(start 271.16024 -304.062384)
		(end 270.98752 -304.096674)
		(width 0.18288)
		(layer "In11.Cu")
		(net "M_D_CPU0_SA_DQS_DN<1>")
	)
	(segment
		(start 341.176864 -277.84679)
		(end 341.162132 -277.838154)
		(width 0.088646)
		(layer "In11.Cu")
		(net "M_D_CPU0_SA_DQS_DN<1>")
	)
	(segment
		(start 310.54675 -301.724822)
		(end 310.262778 -301.44085)
		(width 0.18288)
		(layer "In11.Cu")
		(net "M_D_CPU0_SA_DQS_DN<1>")
	)
	(segment
		(start 294.075866 -309.38851)
		(end 293.788338 -309.101236)
		(width 0.18288)
		(layer "In11.Cu")
		(net "M_D_CPU0_SA_DQS_DN<1>")
	)
	(segment
		(start 272.468086 -305.197002)
		(end 272.133822 -304.862738)
		(width 0.18288)
		(layer "In11.Cu")
		(net "M_D_CPU0_SA_DQS_DN<1>")
	)
	(segment
		(start 345.564206 -277.701248)
		(end 345.310968 -277.847044)
		(width 0.088646)
		(layer "In11.Cu")
		(net "M_D_CPU0_SA_DQS_DN<1>")
	)
	(segment
		(start 331.627988 -282.024582)
		(end 330.801472 -282.024582)
		(width 0.18288)
		(layer "In11.Cu")
		(net "M_D_CPU0_SA_DQS_DN<1>")
	)
	(segment
		(start 279.342596 -309.37073)
		(end 278.69769 -309.37073)
		(width 0.18288)
		(layer "In11.Cu")
		(net "M_D_CPU0_SA_DQS_DN<1>")
	)
	(segment
		(start 301.381922 -307.310282)
		(end 301.381922 -307.310028)
		(width 0.18288)
		(layer "In11.Cu")
		(net "M_D_CPU0_SA_DQS_DN<1>")
	)
	(segment
		(start 271.650968 -304.540158)
		(end 271.616678 -304.367438)
		(width 0.18288)
		(layer "In11.Cu")
		(net "M_D_CPU0_SA_DQS_DN<1>")
	)
	(segment
		(start 334.38592 -278.750014)
		(end 334.302862 -278.832056)
		(width 0.088646)
		(layer "In11.Cu")
		(net "M_D_CPU0_SA_DQS_DN<1>")
	)
	(segment
		(start 340.237064 -277.84679)
		(end 340.222332 -277.838154)
		(width 0.088646)
		(layer "In11.Cu")
		(net "M_D_CPU0_SA_DQS_DN<1>")
	)
	(segment
		(start 308.070758 -302.349154)
		(end 307.158136 -302.72736)
		(width 0.18288)
		(layer "In11.Cu")
		(net "M_D_CPU0_SA_DQS_DN<1>")
	)
	(segment
		(start 335.068164 -278.66086)
		(end 335.067656 -278.661114)
		(width 0.088646)
		(layer "In11.Cu")
		(net "M_D_CPU0_SA_DQS_DN<1>")
	)
	(segment
		(start 275.488654 -308.59857)
		(end 274.98548 -307.38445)
		(width 0.18288)
		(layer "In11.Cu")
		(net "M_D_CPU0_SA_DQS_DN<1>")
	)
	(segment
		(start 313.869578 -300.591728)
		(end 313.611514 -300.849792)
		(width 0.18288)
		(layer "In11.Cu")
		(net "M_D_CPU0_SA_DQS_DN<1>")
	)
	(segment
		(start 276.38883 -309.499)
		(end 275.488654 -308.59857)
		(width 0.18288)
		(layer "In11.Cu")
		(net "M_D_CPU0_SA_DQS_DN<1>")
	)
	(segment
		(start 273.711924 -305.712622)
		(end 273.644614 -305.549554)
		(width 0.18288)
		(layer "In11.Cu")
		(net "M_D_CPU0_SA_DQS_DN<1>")
	)
	(segment
		(start 290.0299 -309.078376)
		(end 289.90544 -309.202836)
		(width 0.18288)
		(layer "In11.Cu")
		(net "M_D_CPU0_SA_DQS_DN<1>")
	)
	(segment
		(start 296.366946 -309.363618)
		(end 295.386252 -309.363618)
		(width 0.18288)
		(layer "In11.Cu")
		(net "M_D_CPU0_SA_DQS_DN<1>")
	)
	(segment
		(start 305.49215 -303.837848)
		(end 305.329082 -303.905158)
		(width 0.18288)
		(layer "In11.Cu")
		(net "M_D_CPU0_SA_DQS_DN<1>")
	)
	(segment
		(start 272.974816 -305.406806)
		(end 272.468086 -305.197002)
		(width 0.18288)
		(layer "In11.Cu")
		(net "M_D_CPU0_SA_DQS_DN<1>")
	)
	(segment
		(start 274.337526 -305.971702)
		(end 273.711924 -305.712622)
		(width 0.18288)
		(layer "In11.Cu")
		(net "M_D_CPU0_SA_DQS_DN<1>")
	)
	(segment
		(start 281.152092 -309.367682)
		(end 280.274268 -309.367682)
		(width 0.18288)
		(layer "In11.Cu")
		(net "M_D_CPU0_SA_DQS_DN<1>")
	)
	(segment
		(start 332.076044 -281.576526)
		(end 331.627988 -282.024582)
		(width 0.18288)
		(layer "In11.Cu")
		(net "M_D_CPU0_SA_DQS_DN<1>")
	)
	(segment
		(start 303.551844 -306.411376)
		(end 303.389284 -306.344066)
		(width 0.18288)
		(layer "In11.Cu")
		(net "M_D_CPU0_SA_DQS_DN<1>")
	)
	(segment
		(start 264.988802 -302.97628)
		(end 264.729214 -302.716692)
		(width 0.18288)
		(layer "In11.Cu")
		(net "M_D_CPU0_SA_DQS_DN<1>")
	)
	(segment
		(start 266.738354 -304.008536)
		(end 266.525502 -304.008536)
		(width 0.18288)
		(layer "In11.Cu")
		(net "M_D_CPU0_SA_DQS_DN<1>")
	)
	(segment
		(start 305.119024 -304.412142)
		(end 305.186588 -304.574702)
		(width 0.18288)
		(layer "In11.Cu")
		(net "M_D_CPU0_SA_DQS_DN<1>")
	)
	(segment
		(start 304.833528 -305.426618)
		(end 304.058574 -306.201572)
		(width 0.18288)
		(layer "In11.Cu")
		(net "M_D_CPU0_SA_DQS_DN<1>")
	)
	(segment
		(start 278.69769 -309.37073)
		(end 278.254714 -309.813706)
		(width 0.18288)
		(layer "In11.Cu")
		(net "M_D_CPU0_SA_DQS_DN<1>")
	)
	(segment
		(start 283.723334 -308.240938)
		(end 283.47162 -308.492652)
		(width 0.18288)
		(layer "In11.Cu")
		(net "M_D_CPU0_SA_DQS_DN<1>")
	)
	(segment
		(start 316.625224 -299.172122)
		(end 316.449202 -299.172122)
		(width 0.18288)
		(layer "In11.Cu")
		(net "M_D_CPU0_SA_DQS_DN<1>")
	)
	(segment
		(start 272.133822 -304.862738)
		(end 271.650968 -304.540158)
		(width 0.18288)
		(layer "In11.Cu")
		(net "M_D_CPU0_SA_DQS_DN<1>")
	)
	(segment
		(start 332.160372 -281.576526)
		(end 332.076044 -281.576526)
		(width 0.088646)
		(layer "In11.Cu")
		(net "M_D_CPU0_SA_DQS_DN<1>")
	)
	(segment
		(start 344.936318 -277.84679)
		(end 344.936064 -277.84679)
		(width 0.088646)
		(layer "In11.Cu")
		(net "M_D_CPU0_SA_DQS_DN<1>")
	)
	(segment
		(start 334.302862 -278.832056)
		(end 334.099154 -278.832056)
		(width 0.088646)
		(layer "In11.Cu")
		(net "M_D_CPU0_SA_DQS_DN<1>")
	)
	(segment
		(start 285.0896 -308.393084)
		(end 284.96514 -308.517544)
		(width 0.18288)
		(layer "In11.Cu")
		(net "M_D_CPU0_SA_DQS_DN<1>")
	)
	(segment
		(start 343.056464 -277.84679)
		(end 343.041732 -277.838154)
		(width 0.088646)
		(layer "In11.Cu")
		(net "M_D_CPU0_SA_DQS_DN<1>")
	)
	(segment
		(start 291.952934 -308.966616)
		(end 291.716968 -309.202836)
		(width 0.18288)
		(layer "In11.Cu")
		(net "M_D_CPU0_SA_DQS_DN<1>")
	)
	(segment
		(start 290.57854 -309.078376)
		(end 290.0299 -309.078376)
		(width 0.18288)
		(layer "In11.Cu")
		(net "M_D_CPU0_SA_DQS_DN<1>")
	)
	(segment
		(start 283.47162 -308.492652)
		(end 283.264864 -308.492652)
		(width 0.18288)
		(layer "In11.Cu")
		(net "M_D_CPU0_SA_DQS_DN<1>")
	)
	(segment
		(start 304.058574 -306.201572)
		(end 303.551844 -306.411376)
		(width 0.18288)
		(layer "In11.Cu")
		(net "M_D_CPU0_SA_DQS_DN<1>")
	)
	(segment
		(start 342.116664 -277.84679)
		(end 342.101932 -277.838154)
		(width 0.088646)
		(layer "In11.Cu")
		(net "M_D_CPU0_SA_DQS_DN<1>")
	)
	(segment
		(start 279.997662 -309.091076)
		(end 279.62225 -309.091076)
		(width 0.18288)
		(layer "In11.Cu")
		(net "M_D_CPU0_SA_DQS_DN<1>")
	)
	(segment
		(start 338.742528 -277.840694)
		(end 338.732114 -277.84679)
		(width 0.088646)
		(layer "In11.Cu")
		(net "M_D_CPU0_SA_DQS_DN<1>")
	)
	(segment
		(start 346.031312 -277.638256)
		(end 345.99245 -277.660354)
		(width 0.088646)
		(layer "In11.Cu")
		(net "M_D_CPU0_SA_DQS_DN<1>")
	)
	(segment
		(start 310.262778 -301.44085)
		(end 309.811166 -301.44085)
		(width 0.18288)
		(layer "In11.Cu")
		(net "M_D_CPU0_SA_DQS_DN<1>")
	)
	(segment
		(start 265.400028 -302.97628)
		(end 264.988802 -302.97628)
		(width 0.18288)
		(layer "In11.Cu")
		(net "M_D_CPU0_SA_DQS_DN<1>")
	)
	(segment
		(start 320.733928 -292.092126)
		(end 320.733928 -292.80739)
		(width 0.18288)
		(layer "In11.Cu")
		(net "M_D_CPU0_SA_DQS_DN<1>")
	)
	(segment
		(start 306.239926 -302.72736)
		(end 305.747928 -303.219358)
		(width 0.18288)
		(layer "In11.Cu")
		(net "M_D_CPU0_SA_DQS_DN<1>")
	)
	(segment
		(start 292.421056 -308.772814)
		(end 291.952934 -308.966616)
		(width 0.18288)
		(layer "In11.Cu")
		(net "M_D_CPU0_SA_DQS_DN<1>")
	)
	(arc
		(start 343.43086 -277.84679)
		(mid 343.243662 -277.896933)
		(end 343.056464 -277.84679)
		(width 0.088646)
		(layer "In11.Cu")
		(net "M_D_CPU0_SA_DQS_DN<1>")
	)
	(arc
		(start 342.49106 -277.84679)
		(mid 342.303862 -277.896933)
		(end 342.116664 -277.84679)
		(width 0.088646)
		(layer "In11.Cu")
		(net "M_D_CPU0_SA_DQS_DN<1>")
	)
	(arc
		(start 341.162132 -277.838154)
		(mid 340.885691 -277.770988)
		(end 340.61146 -277.84679)
		(width 0.088646)
		(layer "In11.Cu")
		(net "M_D_CPU0_SA_DQS_DN<1>")
	)
	(arc
		(start 339.67166 -277.84679)
		(mid 339.484462 -277.896933)
		(end 339.297264 -277.84679)
		(width 0.088646)
		(layer "In11.Cu")
		(net "M_D_CPU0_SA_DQS_DN<1>")
	)
	(arc
		(start 340.222332 -277.838154)
		(mid 339.945891 -277.770988)
		(end 339.67166 -277.84679)
		(width 0.088646)
		(layer "In11.Cu")
		(net "M_D_CPU0_SA_DQS_DN<1>")
	)
	(arc
		(start 345.99245 -277.660354)
		(mid 345.917765 -277.690859)
		(end 345.837764 -277.701248)
		(width 0.088646)
		(layer "In11.Cu")
		(net "M_D_CPU0_SA_DQS_DN<1>")
	)
	(arc
		(start 334.503522 -278.66086)
		(mid 334.4418 -278.701584)
		(end 334.38592 -278.750014)
		(width 0.088646)
		(layer "In11.Cu")
		(net "M_D_CPU0_SA_DQS_DN<1>")
	)
	(arc
		(start 336.462878 -277.838408)
		(mid 336.186403 -277.771088)
		(end 335.912206 -277.847044)
		(width 0.088646)
		(layer "In11.Cu")
		(net "M_D_CPU0_SA_DQS_DN<1>")
	)
	(arc
		(start 338.357718 -277.84679)
		(mid 338.080905 -277.770954)
		(end 337.802474 -277.840694)
		(width 0.088646)
		(layer "In11.Cu")
		(net "M_D_CPU0_SA_DQS_DN<1>")
	)
	(arc
		(start 340.61146 -277.84679)
		(mid 340.424262 -277.896933)
		(end 340.237064 -277.84679)
		(width 0.088646)
		(layer "In11.Cu")
		(net "M_D_CPU0_SA_DQS_DN<1>")
	)
	(arc
		(start 344.921332 -277.838154)
		(mid 344.644891 -277.770988)
		(end 344.37066 -277.84679)
		(width 0.088646)
		(layer "In11.Cu")
		(net "M_D_CPU0_SA_DQS_DN<1>")
	)
	(arc
		(start 343.041732 -277.838154)
		(mid 342.765291 -277.770988)
		(end 342.49106 -277.84679)
		(width 0.088646)
		(layer "In11.Cu")
		(net "M_D_CPU0_SA_DQS_DN<1>")
	)
	(arc
		(start 343.981532 -277.838154)
		(mid 343.705091 -277.770988)
		(end 343.43086 -277.84679)
		(width 0.088646)
		(layer "In11.Cu")
		(net "M_D_CPU0_SA_DQS_DN<1>")
	)
	(arc
		(start 337.79206 -277.84679)
		(mid 337.604862 -277.896933)
		(end 337.417664 -277.84679)
		(width 0.088646)
		(layer "In11.Cu")
		(net "M_D_CPU0_SA_DQS_DN<1>")
	)
	(arc
		(start 345.310714 -277.84679)
		(mid 345.123516 -277.896933)
		(end 344.936318 -277.84679)
		(width 0.088646)
		(layer "In11.Cu")
		(net "M_D_CPU0_SA_DQS_DN<1>")
	)
	(arc
		(start 336.852006 -277.847044)
		(mid 336.664808 -277.897187)
		(end 336.47761 -277.847044)
		(width 0.088646)
		(layer "In11.Cu")
		(net "M_D_CPU0_SA_DQS_DN<1>")
	)
	(arc
		(start 339.297264 -277.84679)
		(mid 339.020705 -277.771081)
		(end 338.742528 -277.840694)
		(width 0.088646)
		(layer "In11.Cu")
		(net "M_D_CPU0_SA_DQS_DN<1>")
	)
	(arc
		(start 335.44256 -278.66086)
		(mid 335.255362 -278.711003)
		(end 335.068164 -278.66086)
		(width 0.088646)
		(layer "In11.Cu")
		(net "M_D_CPU0_SA_DQS_DN<1>")
	)
	(arc
		(start 344.37066 -277.84679)
		(mid 344.183462 -277.896933)
		(end 343.996264 -277.84679)
		(width 0.088646)
		(layer "In11.Cu")
		(net "M_D_CPU0_SA_DQS_DN<1>")
	)
	(arc
		(start 342.101932 -277.838154)
		(mid 341.825491 -277.770988)
		(end 341.55126 -277.84679)
		(width 0.088646)
		(layer "In11.Cu")
		(net "M_D_CPU0_SA_DQS_DN<1>")
	)
	(arc
		(start 335.912206 -277.847044)
		(mid 335.709383 -278.047275)
		(end 335.630012 -278.321008)
		(width 0.088646)
		(layer "In11.Cu")
		(net "M_D_CPU0_SA_DQS_DN<1>")
	)
	(arc
		(start 335.067656 -278.661114)
		(mid 334.785635 -278.585558)
		(end 334.503522 -278.66086)
		(width 0.088646)
		(layer "In11.Cu")
		(net "M_D_CPU0_SA_DQS_DN<1>")
	)
	(arc
		(start 338.732114 -277.84679)
		(mid 338.544916 -277.896933)
		(end 338.357718 -277.84679)
		(width 0.088646)
		(layer "In11.Cu")
		(net "M_D_CPU0_SA_DQS_DN<1>")
	)
	(arc
		(start 335.630012 -278.336502)
		(mid 335.582333 -278.519402)
		(end 335.45145 -278.65578)
		(width 0.088646)
		(layer "In11.Cu")
		(net "M_D_CPU0_SA_DQS_DN<1>")
	)
	(arc
		(start 337.417664 -277.84679)
		(mid 337.139938 -277.770945)
		(end 336.860896 -277.84171)
		(width 0.088646)
		(layer "In11.Cu")
		(net "M_D_CPU0_SA_DQS_DN<1>")
	)
	(arc
		(start 341.55126 -277.84679)
		(mid 341.364062 -277.896933)
		(end 341.176864 -277.84679)
		(width 0.088646)
		(layer "In11.Cu")
		(net "M_D_CPU0_SA_DQS_DN<1>")
	)
	(segment
		(start 262.40994 -312.327798)
		(end 261.984744 -312.752994)
		(width 0.20066)
		(layer "F.Cu")
		(net "M_D_CPU0_SA_DQS_DN<0>")
	)
	(segment
		(start 256.629154 -312.066686)
		(end 256.080514 -312.066686)
		(width 0.20066)
		(layer "F.Cu")
		(net "M_D_CPU0_SA_DQS_DN<0>")
	)
	(segment
		(start 259.056378 -312.48096)
		(end 258.852162 -312.48096)
		(width 0.20066)
		(layer "F.Cu")
		(net "M_D_CPU0_SA_DQS_DN<0>")
	)
	(segment
		(start 258.852162 -312.48096)
		(end 258.580128 -312.752994)
		(width 0.20066)
		(layer "F.Cu")
		(net "M_D_CPU0_SA_DQS_DN<0>")
	)
	(segment
		(start 259.05714 -312.48096)
		(end 259.056378 -312.48096)
		(width 0.101854)
		(layer "F.Cu")
		(net "M_D_CPU0_SA_DQS_DN<0>")
	)
	(segment
		(start 262.816594 -312.327798)
		(end 262.40994 -312.327798)
		(width 0.20066)
		(layer "F.Cu")
		(net "M_D_CPU0_SA_DQS_DN<0>")
	)
	(segment
		(start 261.984744 -312.752994)
		(end 261.798054 -312.752994)
		(width 0.20066)
		(layer "F.Cu")
		(net "M_D_CPU0_SA_DQS_DN<0>")
	)
	(segment
		(start 257.404108 -312.327798)
		(end 256.890266 -312.327798)
		(width 0.20066)
		(layer "F.Cu")
		(net "M_D_CPU0_SA_DQS_DN<0>")
	)
	(segment
		(start 259.067808 -312.491628)
		(end 259.05714 -312.48096)
		(width 0.101854)
		(layer "F.Cu")
		(net "M_D_CPU0_SA_DQS_DN<0>")
	)
	(segment
		(start 261.798054 -312.752994)
		(end 261.536688 -312.491628)
		(width 0.20066)
		(layer "F.Cu")
		(net "M_D_CPU0_SA_DQS_DN<0>")
	)
	(segment
		(start 256.890266 -312.327798)
		(end 256.629154 -312.066686)
		(width 0.20066)
		(layer "F.Cu")
		(net "M_D_CPU0_SA_DQS_DN<0>")
	)
	(segment
		(start 263.624314 -312.066686)
		(end 263.077706 -312.066686)
		(width 0.20066)
		(layer "F.Cu")
		(net "M_D_CPU0_SA_DQS_DN<0>")
	)
	(segment
		(start 261.381494 -312.491628)
		(end 259.067808 -312.491628)
		(width 0.1016)
		(layer "F.Cu")
		(net "M_D_CPU0_SA_DQS_DN<0>")
	)
	(segment
		(start 264.729214 -312.066686)
		(end 263.624314 -312.066686)
		(width 0.20066)
		(layer "F.Cu")
		(net "M_D_CPU0_SA_DQS_DN<0>")
	)
	(segment
		(start 258.580128 -312.752994)
		(end 258.040124 -312.752994)
		(width 0.20066)
		(layer "F.Cu")
		(net "M_D_CPU0_SA_DQS_DN<0>")
	)
	(segment
		(start 258.040124 -312.752994)
		(end 257.404108 -312.327798)
		(width 0.20066)
		(layer "F.Cu")
		(net "M_D_CPU0_SA_DQS_DN<0>")
	)
	(segment
		(start 263.077706 -312.066686)
		(end 262.816594 -312.327798)
		(width 0.20066)
		(layer "F.Cu")
		(net "M_D_CPU0_SA_DQS_DN<0>")
	)
	(segment
		(start 261.536688 -312.491628)
		(end 261.381494 -312.491628)
		(width 0.20066)
		(layer "F.Cu")
		(net "M_D_CPU0_SA_DQS_DN<0>")
	)
	(arc
		(start 342.773762 -274.54479)
		(mid 342.773825 -274.81276)
		(end 342.774016 -275.08073)
		(width 0.20066)
		(layer "F.Cu")
		(net "M_D_CPU0_SA_DQS_DN<0>")
	)
	(segment
		(start 330.32827 -281.470608)
		(end 329.940158 -281.85872)
		(width 0.18288)
		(layer "In6.Cu")
		(net "M_D_CPU0_SA_DQS_DN<0>")
	)
	(segment
		(start 323.276214 -288.522664)
		(end 323.276214 -288.698686)
		(width 0.18288)
		(layer "In6.Cu")
		(net "M_D_CPU0_SA_DQS_DN<0>")
	)
	(segment
		(start 280.03754 -313.341512)
		(end 279.593802 -313.341512)
		(width 0.18288)
		(layer "In6.Cu")
		(net "M_D_CPU0_SA_DQS_DN<0>")
	)
	(segment
		(start 322.324222 -289.474656)
		(end 322.324222 -289.650678)
		(width 0.18288)
		(layer "In6.Cu")
		(net "M_D_CPU0_SA_DQS_DN<0>")
	)
	(segment
		(start 341.096346 -275.396452)
		(end 341.081614 -275.405088)
		(width 0.088646)
		(layer "In6.Cu")
		(net "M_D_CPU0_SA_DQS_DN<0>")
	)
	(segment
		(start 321.37223 -290.426648)
		(end 321.37223 -290.60267)
		(width 0.18288)
		(layer "In6.Cu")
		(net "M_D_CPU0_SA_DQS_DN<0>")
	)
	(segment
		(start 295.968928 -309.08117)
		(end 295.69791 -309.352188)
		(width 0.18288)
		(layer "In6.Cu")
		(net "M_D_CPU0_SA_DQS_DN<0>")
	)
	(segment
		(start 284.394402 -314.452254)
		(end 284.133798 -314.19165)
		(width 0.18288)
		(layer "In6.Cu")
		(net "M_D_CPU0_SA_DQS_DN<0>")
	)
	(segment
		(start 299.542962 -306.802028)
		(end 299.282612 -306.541678)
		(width 0.18288)
		(layer "In6.Cu")
		(net "M_D_CPU0_SA_DQS_DN<0>")
	)
	(segment
		(start 313.60872 -299.189648)
		(end 312.656982 -299.189648)
		(width 0.18288)
		(layer "In6.Cu")
		(net "M_D_CPU0_SA_DQS_DN<0>")
	)
	(segment
		(start 307.58384 -300.93793)
		(end 306.345336 -302.176434)
		(width 0.18288)
		(layer "In6.Cu")
		(net "M_D_CPU0_SA_DQS_DN<0>")
	)
	(segment
		(start 328.988166 -282.810712)
		(end 328.988166 -282.986734)
		(width 0.18288)
		(layer "In6.Cu")
		(net "M_D_CPU0_SA_DQS_DN<0>")
	)
	(segment
		(start 323.276214 -288.698686)
		(end 322.888356 -289.086544)
		(width 0.18288)
		(layer "In6.Cu")
		(net "M_D_CPU0_SA_DQS_DN<0>")
	)
	(segment
		(start 310.51627 -300.01337)
		(end 310.24449 -299.74159)
		(width 0.18288)
		(layer "In6.Cu")
		(net "M_D_CPU0_SA_DQS_DN<0>")
	)
	(segment
		(start 320.420238 -291.554662)
		(end 315.508132 -296.466768)
		(width 0.18288)
		(layer "In6.Cu")
		(net "M_D_CPU0_SA_DQS_DN<0>")
	)
	(segment
		(start 283.120592 -314.434728)
		(end 282.469082 -313.782964)
		(width 0.18288)
		(layer "In6.Cu")
		(net "M_D_CPU0_SA_DQS_DN<0>")
	)
	(segment
		(start 323.664326 -288.134552)
		(end 323.276214 -288.522664)
		(width 0.18288)
		(layer "In6.Cu")
		(net "M_D_CPU0_SA_DQS_DN<0>")
	)
	(segment
		(start 306.139088 -302.673258)
		(end 304.5333 -304.279046)
		(width 0.18288)
		(layer "In6.Cu")
		(net "M_D_CPU0_SA_DQS_DN<0>")
	)
	(segment
		(start 315.508132 -296.466768)
		(end 315.508132 -298.500292)
		(width 0.18288)
		(layer "In6.Cu")
		(net "M_D_CPU0_SA_DQS_DN<0>")
	)
	(segment
		(start 312.656982 -299.189648)
		(end 312.092086 -299.754544)
		(width 0.18288)
		(layer "In6.Cu")
		(net "M_D_CPU0_SA_DQS_DN<0>")
	)
	(segment
		(start 321.936364 -290.038536)
		(end 321.760342 -290.038536)
		(width 0.18288)
		(layer "In6.Cu")
		(net "M_D_CPU0_SA_DQS_DN<0>")
	)
	(segment
		(start 309.494428 -299.991018)
		(end 308.956202 -299.991018)
		(width 0.18288)
		(layer "In6.Cu")
		(net "M_D_CPU0_SA_DQS_DN<0>")
	)
	(segment
		(start 333.657956 -278.806656)
		(end 332.467966 -279.996646)
		(width 0.088646)
		(layer "In6.Cu")
		(net "M_D_CPU0_SA_DQS_DN<0>")
	)
	(segment
		(start 326.520302 -285.278576)
		(end 326.13219 -285.666688)
		(width 0.18288)
		(layer "In6.Cu")
		(net "M_D_CPU0_SA_DQS_DN<0>")
	)
	(segment
		(start 300.754034 -306.538884)
		(end 300.119288 -306.802028)
		(width 0.18288)
		(layer "In6.Cu")
		(net "M_D_CPU0_SA_DQS_DN<0>")
	)
	(segment
		(start 327.472294 -284.326584)
		(end 327.084182 -284.714696)
		(width 0.18288)
		(layer "In6.Cu")
		(net "M_D_CPU0_SA_DQS_DN<0>")
	)
	(segment
		(start 293.54018 -309.854092)
		(end 292.59403 -310.246014)
		(width 0.18288)
		(layer "In6.Cu")
		(net "M_D_CPU0_SA_DQS_DN<0>")
	)
	(segment
		(start 337.509612 -276.69871)
		(end 337.509612 -276.708616)
		(width 0.088646)
		(layer "In6.Cu")
		(net "M_D_CPU0_SA_DQS_DN<0>")
	)
	(segment
		(start 295.968928 -308.437534)
		(end 295.968928 -309.08117)
		(width 0.18288)
		(layer "In6.Cu")
		(net "M_D_CPU0_SA_DQS_DN<0>")
	)
	(segment
		(start 323.840348 -288.134552)
		(end 323.664326 -288.134552)
		(width 0.18288)
		(layer "In6.Cu")
		(net "M_D_CPU0_SA_DQS_DN<0>")
	)
	(segment
		(start 328.036174 -283.938726)
		(end 327.648316 -284.326584)
		(width 0.18288)
		(layer "In6.Cu")
		(net "M_D_CPU0_SA_DQS_DN<0>")
	)
	(segment
		(start 292.59403 -310.246014)
		(end 291.936932 -310.902604)
		(width 0.18288)
		(layer "In6.Cu")
		(net "M_D_CPU0_SA_DQS_DN<0>")
	)
	(segment
		(start 337.32216 -277.032974)
		(end 337.309968 -277.040086)
		(width 0.088646)
		(layer "In6.Cu")
		(net "M_D_CPU0_SA_DQS_DN<0>")
	)
	(segment
		(start 295.442894 -309.352188)
		(end 295.182544 -309.091838)
		(width 0.18288)
		(layer "In6.Cu")
		(net "M_D_CPU0_SA_DQS_DN<0>")
	)
	(segment
		(start 342.742266 -275.196554)
		(end 342.703404 -275.218652)
		(width 0.088646)
		(layer "In6.Cu")
		(net "M_D_CPU0_SA_DQS_DN<0>")
	)
	(segment
		(start 295.69791 -309.352188)
		(end 295.442894 -309.352188)
		(width 0.18288)
		(layer "In6.Cu")
		(net "M_D_CPU0_SA_DQS_DN<0>")
	)
	(segment
		(start 329.940158 -282.034742)
		(end 329.5523 -282.4226)
		(width 0.18288)
		(layer "In6.Cu")
		(net "M_D_CPU0_SA_DQS_DN<0>")
	)
	(segment
		(start 340.151974 -275.398992)
		(end 340.14156 -275.405088)
		(width 0.088646)
		(layer "In6.Cu")
		(net "M_D_CPU0_SA_DQS_DN<0>")
	)
	(segment
		(start 298.544234 -306.778914)
		(end 297.99534 -306.778914)
		(width 0.18288)
		(layer "In6.Cu")
		(net "M_D_CPU0_SA_DQS_DN<0>")
	)
	(segment
		(start 326.13219 -285.84271)
		(end 325.744332 -286.230568)
		(width 0.18288)
		(layer "In6.Cu")
		(net "M_D_CPU0_SA_DQS_DN<0>")
	)
	(segment
		(start 312.092086 -299.754544)
		(end 311.242456 -299.754544)
		(width 0.18288)
		(layer "In6.Cu")
		(net "M_D_CPU0_SA_DQS_DN<0>")
	)
	(segment
		(start 297.99534 -306.778914)
		(end 297.335956 -307.438044)
		(width 0.18288)
		(layer "In6.Cu")
		(net "M_D_CPU0_SA_DQS_DN<0>")
	)
	(segment
		(start 297.335956 -307.438044)
		(end 296.708068 -307.69814)
		(width 0.18288)
		(layer "In6.Cu")
		(net "M_D_CPU0_SA_DQS_DN<0>")
	)
	(segment
		(start 299.282612 -306.541678)
		(end 298.78147 -306.541678)
		(width 0.18288)
		(layer "In6.Cu")
		(net "M_D_CPU0_SA_DQS_DN<0>")
	)
	(segment
		(start 327.084182 -284.890718)
		(end 326.696324 -285.278576)
		(width 0.18288)
		(layer "In6.Cu")
		(net "M_D_CPU0_SA_DQS_DN<0>")
	)
	(segment
		(start 338.272374 -275.398992)
		(end 338.26196 -275.405088)
		(width 0.088646)
		(layer "In6.Cu")
		(net "M_D_CPU0_SA_DQS_DN<0>")
	)
	(segment
		(start 320.984372 -290.990528)
		(end 320.80835 -290.990528)
		(width 0.18288)
		(layer "In6.Cu")
		(net "M_D_CPU0_SA_DQS_DN<0>")
	)
	(segment
		(start 325.744332 -286.230568)
		(end 325.56831 -286.230568)
		(width 0.18288)
		(layer "In6.Cu")
		(net "M_D_CPU0_SA_DQS_DN<0>")
	)
	(segment
		(start 335.53781 -277.847044)
		(end 335.523078 -277.838408)
		(width 0.088646)
		(layer "In6.Cu")
		(net "M_D_CPU0_SA_DQS_DN<0>")
	)
	(segment
		(start 336.860896 -277.841964)
		(end 336.852006 -277.847044)
		(width 0.088646)
		(layer "In6.Cu")
		(net "M_D_CPU0_SA_DQS_DN<0>")
	)
	(segment
		(start 314.548012 -299.139356)
		(end 314.301124 -298.892468)
		(width 0.18288)
		(layer "In6.Cu")
		(net "M_D_CPU0_SA_DQS_DN<0>")
	)
	(segment
		(start 295.182544 -309.091838)
		(end 294.681402 -309.091838)
		(width 0.18288)
		(layer "In6.Cu")
		(net "M_D_CPU0_SA_DQS_DN<0>")
	)
	(segment
		(start 310.24449 -299.74159)
		(end 309.743856 -299.74159)
		(width 0.18288)
		(layer "In6.Cu")
		(net "M_D_CPU0_SA_DQS_DN<0>")
	)
	(segment
		(start 339.212428 -275.398992)
		(end 339.202014 -275.405088)
		(width 0.088646)
		(layer "In6.Cu")
		(net "M_D_CPU0_SA_DQS_DN<0>")
	)
	(segment
		(start 327.084182 -284.714696)
		(end 327.084182 -284.890718)
		(width 0.18288)
		(layer "In6.Cu")
		(net "M_D_CPU0_SA_DQS_DN<0>")
	)
	(segment
		(start 294.681402 -309.091838)
		(end 294.432228 -309.341012)
		(width 0.18288)
		(layer "In6.Cu")
		(net "M_D_CPU0_SA_DQS_DN<0>")
	)
	(segment
		(start 282.112212 -313.635136)
		(end 280.331164 -313.635136)
		(width 0.18288)
		(layer "In6.Cu")
		(net "M_D_CPU0_SA_DQS_DN<0>")
	)
	(segment
		(start 278.016208 -312.630312)
		(end 276.709378 -312.089292)
		(width 0.18288)
		(layer "In6.Cu")
		(net "M_D_CPU0_SA_DQS_DN<0>")
	)
	(segment
		(start 298.78147 -306.541678)
		(end 298.544234 -306.778914)
		(width 0.18288)
		(layer "In6.Cu")
		(net "M_D_CPU0_SA_DQS_DN<0>")
	)
	(segment
		(start 268.634972 -312.491628)
		(end 268.372844 -312.753756)
		(width 0.18288)
		(layer "In6.Cu")
		(net "M_D_CPU0_SA_DQS_DN<0>")
	)
	(segment
		(start 320.80835 -290.990528)
		(end 320.420238 -291.37864)
		(width 0.18288)
		(layer "In6.Cu")
		(net "M_D_CPU0_SA_DQS_DN<0>")
	)
	(segment
		(start 329.376278 -282.4226)
		(end 328.988166 -282.810712)
		(width 0.18288)
		(layer "In6.Cu")
		(net "M_D_CPU0_SA_DQS_DN<0>")
	)
	(segment
		(start 322.888356 -289.086544)
		(end 322.712334 -289.086544)
		(width 0.18288)
		(layer "In6.Cu")
		(net "M_D_CPU0_SA_DQS_DN<0>")
	)
	(segment
		(start 272.431002 -312.76671)
		(end 269.325852 -312.76671)
		(width 0.18288)
		(layer "In6.Cu")
		(net "M_D_CPU0_SA_DQS_DN<0>")
	)
	(segment
		(start 332.077568 -280.710386)
		(end 332.017878 -280.650696)
		(width 0.088646)
		(layer "In6.Cu")
		(net "M_D_CPU0_SA_DQS_DN<0>")
	)
	(segment
		(start 333.657956 -278.194516)
		(end 333.657956 -278.806656)
		(width 0.088646)
		(layer "In6.Cu")
		(net "M_D_CPU0_SA_DQS_DN<0>")
	)
	(segment
		(start 332.017878 -280.650696)
		(end 331.99451 -280.650696)
		(width 0.088646)
		(layer "In6.Cu")
		(net "M_D_CPU0_SA_DQS_DN<0>")
	)
	(segment
		(start 309.743856 -299.74159)
		(end 309.494428 -299.991018)
		(width 0.18288)
		(layer "In6.Cu")
		(net "M_D_CPU0_SA_DQS_DN<0>")
	)
	(segment
		(start 328.988166 -282.986734)
		(end 328.600308 -283.374592)
		(width 0.18288)
		(layer "In6.Cu")
		(net "M_D_CPU0_SA_DQS_DN<0>")
	)
	(segment
		(start 337.80095 -276.214078)
		(end 337.792822 -276.21865)
		(width 0.088646)
		(layer "In6.Cu")
		(net "M_D_CPU0_SA_DQS_DN<0>")
	)
	(segment
		(start 322.324222 -289.650678)
		(end 321.936364 -290.038536)
		(width 0.18288)
		(layer "In6.Cu")
		(net "M_D_CPU0_SA_DQS_DN<0>")
	)
	(segment
		(start 324.228206 -287.746694)
		(end 323.840348 -288.134552)
		(width 0.18288)
		(layer "In6.Cu")
		(net "M_D_CPU0_SA_DQS_DN<0>")
	)
	(segment
		(start 300.119288 -306.802028)
		(end 299.542962 -306.802028)
		(width 0.18288)
		(layer "In6.Cu")
		(net "M_D_CPU0_SA_DQS_DN<0>")
	)
	(segment
		(start 269.325852 -312.76671)
		(end 269.05077 -312.491628)
		(width 0.18288)
		(layer "In6.Cu")
		(net "M_D_CPU0_SA_DQS_DN<0>")
	)
	(segment
		(start 267.267944 -312.26379)
		(end 266.908026 -312.114946)
		(width 0.18288)
		(layer "In6.Cu")
		(net "M_D_CPU0_SA_DQS_DN<0>")
	)
	(segment
		(start 328.036174 -283.762704)
		(end 328.036174 -283.938726)
		(width 0.18288)
		(layer "In6.Cu")
		(net "M_D_CPU0_SA_DQS_DN<0>")
	)
	(segment
		(start 279.593802 -313.341512)
		(end 279.348184 -313.58713)
		(width 0.18288)
		(layer "In6.Cu")
		(net "M_D_CPU0_SA_DQS_DN<0>")
	)
	(segment
		(start 265.719052 -312.336942)
		(end 264.99947 -312.336942)
		(width 0.18288)
		(layer "In6.Cu")
		(net "M_D_CPU0_SA_DQS_DN<0>")
	)
	(segment
		(start 331.324204 -280.650696)
		(end 330.504292 -281.470608)
		(width 0.18288)
		(layer "In6.Cu")
		(net "M_D_CPU0_SA_DQS_DN<0>")
	)
	(segment
		(start 321.760342 -290.038536)
		(end 321.37223 -290.426648)
		(width 0.18288)
		(layer "In6.Cu")
		(net "M_D_CPU0_SA_DQS_DN<0>")
	)
	(segment
		(start 278.972772 -313.58713)
		(end 278.016208 -312.630312)
		(width 0.18288)
		(layer "In6.Cu")
		(net "M_D_CPU0_SA_DQS_DN<0>")
	)
	(segment
		(start 283.451046 -314.434728)
		(end 283.120592 -314.434728)
		(width 0.18288)
		(layer "In6.Cu")
		(net "M_D_CPU0_SA_DQS_DN<0>")
	)
	(segment
		(start 325.180198 -286.61868)
		(end 325.180198 -286.794702)
		(width 0.18288)
		(layer "In6.Cu")
		(net "M_D_CPU0_SA_DQS_DN<0>")
	)
	(segment
		(start 311.242456 -299.754544)
		(end 310.98363 -300.01337)
		(width 0.18288)
		(layer "In6.Cu")
		(net "M_D_CPU0_SA_DQS_DN<0>")
	)
	(segment
		(start 282.469082 -313.782964)
		(end 282.112212 -313.635136)
		(width 0.18288)
		(layer "In6.Cu")
		(net "M_D_CPU0_SA_DQS_DN<0>")
	)
	(segment
		(start 333.915766 -277.936706)
		(end 333.657956 -278.194516)
		(width 0.088646)
		(layer "In6.Cu")
		(net "M_D_CPU0_SA_DQS_DN<0>")
	)
	(segment
		(start 334.59801 -277.847044)
		(end 334.583278 -277.838408)
		(width 0.088646)
		(layer "In6.Cu")
		(net "M_D_CPU0_SA_DQS_DN<0>")
	)
	(segment
		(start 283.694124 -314.19165)
		(end 283.451046 -314.434728)
		(width 0.18288)
		(layer "In6.Cu")
		(net "M_D_CPU0_SA_DQS_DN<0>")
	)
	(segment
		(start 336.47761 -277.847044)
		(end 336.462878 -277.838408)
		(width 0.088646)
		(layer "In6.Cu")
		(net "M_D_CPU0_SA_DQS_DN<0>")
	)
	(segment
		(start 326.13219 -285.666688)
		(end 326.13219 -285.84271)
		(width 0.18288)
		(layer "In6.Cu")
		(net "M_D_CPU0_SA_DQS_DN<0>")
	)
	(segment
		(start 306.345336 -302.176434)
		(end 306.139088 -302.673258)
		(width 0.18288)
		(layer "In6.Cu")
		(net "M_D_CPU0_SA_DQS_DN<0>")
	)
	(segment
		(start 301.937674 -305.355244)
		(end 300.754034 -306.538884)
		(width 0.18288)
		(layer "In6.Cu")
		(net "M_D_CPU0_SA_DQS_DN<0>")
	)
	(segment
		(start 268.372844 -312.753756)
		(end 267.757656 -312.753756)
		(width 0.18288)
		(layer "In6.Cu")
		(net "M_D_CPU0_SA_DQS_DN<0>")
	)
	(segment
		(start 342.27516 -275.259546)
		(end 342.021922 -275.405342)
		(width 0.088646)
		(layer "In6.Cu")
		(net "M_D_CPU0_SA_DQS_DN<0>")
	)
	(segment
		(start 314.869068 -299.139356)
		(end 314.548012 -299.139356)
		(width 0.18288)
		(layer "In6.Cu")
		(net "M_D_CPU0_SA_DQS_DN<0>")
	)
	(segment
		(start 264.99947 -312.336942)
		(end 264.729214 -312.066686)
		(width 0.18288)
		(layer "In6.Cu")
		(net "M_D_CPU0_SA_DQS_DN<0>")
	)
	(segment
		(start 329.5523 -282.4226)
		(end 329.376278 -282.4226)
		(width 0.18288)
		(layer "In6.Cu")
		(net "M_D_CPU0_SA_DQS_DN<0>")
	)
	(segment
		(start 337.792822 -276.21865)
		(end 337.79206 -276.219158)
		(width 0.088646)
		(layer "In6.Cu")
		(net "M_D_CPU0_SA_DQS_DN<0>")
	)
	(segment
		(start 291.936932 -310.902604)
		(end 286.818578 -313.022742)
		(width 0.18288)
		(layer "In6.Cu")
		(net "M_D_CPU0_SA_DQS_DN<0>")
	)
	(segment
		(start 337.33105 -277.027894)
		(end 337.32216 -277.032974)
		(width 0.088646)
		(layer "In6.Cu")
		(net "M_D_CPU0_SA_DQS_DN<0>")
	)
	(segment
		(start 294.432228 -309.341012)
		(end 294.053514 -309.341012)
		(width 0.18288)
		(layer "In6.Cu")
		(net "M_D_CPU0_SA_DQS_DN<0>")
	)
	(segment
		(start 321.37223 -290.60267)
		(end 320.984372 -290.990528)
		(width 0.18288)
		(layer "In6.Cu")
		(net "M_D_CPU0_SA_DQS_DN<0>")
	)
	(segment
		(start 326.696324 -285.278576)
		(end 326.520302 -285.278576)
		(width 0.18288)
		(layer "In6.Cu")
		(net "M_D_CPU0_SA_DQS_DN<0>")
	)
	(segment
		(start 324.79234 -287.18256)
		(end 324.616318 -287.18256)
		(width 0.18288)
		(layer "In6.Cu")
		(net "M_D_CPU0_SA_DQS_DN<0>")
	)
	(segment
		(start 308.956202 -299.991018)
		(end 308.309772 -300.637194)
		(width 0.18288)
		(layer "In6.Cu")
		(net "M_D_CPU0_SA_DQS_DN<0>")
	)
	(segment
		(start 310.98363 -300.01337)
		(end 310.51627 -300.01337)
		(width 0.18288)
		(layer "In6.Cu")
		(net "M_D_CPU0_SA_DQS_DN<0>")
	)
	(segment
		(start 304.5333 -304.279046)
		(end 301.937674 -305.355244)
		(width 0.18288)
		(layer "In6.Cu")
		(net "M_D_CPU0_SA_DQS_DN<0>")
	)
	(segment
		(start 342.774016 -275.08073)
		(end 342.742266 -275.196554)
		(width 0.088646)
		(layer "In6.Cu")
		(net "M_D_CPU0_SA_DQS_DN<0>")
	)
	(segment
		(start 269.05077 -312.491628)
		(end 268.634972 -312.491628)
		(width 0.18288)
		(layer "In6.Cu")
		(net "M_D_CPU0_SA_DQS_DN<0>")
	)
	(segment
		(start 284.133798 -314.19165)
		(end 283.694124 -314.19165)
		(width 0.18288)
		(layer "In6.Cu")
		(net "M_D_CPU0_SA_DQS_DN<0>")
	)
	(segment
		(start 331.99451 -280.650696)
		(end 331.324204 -280.650696)
		(width 0.18288)
		(layer "In6.Cu")
		(net "M_D_CPU0_SA_DQS_DN<0>")
	)
	(segment
		(start 266.908026 -312.114946)
		(end 266.2555 -312.114946)
		(width 0.18288)
		(layer "In6.Cu")
		(net "M_D_CPU0_SA_DQS_DN<0>")
	)
	(segment
		(start 325.180198 -286.794702)
		(end 324.79234 -287.18256)
		(width 0.18288)
		(layer "In6.Cu")
		(net "M_D_CPU0_SA_DQS_DN<0>")
	)
	(segment
		(start 284.93339 -314.452254)
		(end 284.394402 -314.452254)
		(width 0.18288)
		(layer "In6.Cu")
		(net "M_D_CPU0_SA_DQS_DN<0>")
	)
	(segment
		(start 337.979512 -275.876258)
		(end 337.979512 -275.8948)
		(width 0.088646)
		(layer "In6.Cu")
		(net "M_D_CPU0_SA_DQS_DN<0>")
	)
	(segment
		(start 274.066762 -312.089292)
		(end 272.431002 -312.76671)
		(width 0.18288)
		(layer "In6.Cu")
		(net "M_D_CPU0_SA_DQS_DN<0>")
	)
	(segment
		(start 294.053514 -309.341012)
		(end 293.54018 -309.854092)
		(width 0.18288)
		(layer "In6.Cu")
		(net "M_D_CPU0_SA_DQS_DN<0>")
	)
	(segment
		(start 286.818578 -313.022742)
		(end 285.711138 -314.130182)
		(width 0.18288)
		(layer "In6.Cu")
		(net "M_D_CPU0_SA_DQS_DN<0>")
	)
	(segment
		(start 296.708068 -307.69814)
		(end 295.968928 -308.437534)
		(width 0.18288)
		(layer "In6.Cu")
		(net "M_D_CPU0_SA_DQS_DN<0>")
	)
	(segment
		(start 279.348184 -313.58713)
		(end 278.972772 -313.58713)
		(width 0.18288)
		(layer "In6.Cu")
		(net "M_D_CPU0_SA_DQS_DN<0>")
	)
	(segment
		(start 329.940158 -281.85872)
		(end 329.940158 -282.034742)
		(width 0.18288)
		(layer "In6.Cu")
		(net "M_D_CPU0_SA_DQS_DN<0>")
	)
	(segment
		(start 276.709378 -312.089292)
		(end 274.066762 -312.089292)
		(width 0.18288)
		(layer "In6.Cu")
		(net "M_D_CPU0_SA_DQS_DN<0>")
	)
	(segment
		(start 280.331164 -313.635136)
		(end 280.03754 -313.341512)
		(width 0.18288)
		(layer "In6.Cu")
		(net "M_D_CPU0_SA_DQS_DN<0>")
	)
	(segment
		(start 315.508132 -298.500292)
		(end 314.869068 -299.139356)
		(width 0.18288)
		(layer "In6.Cu")
		(net "M_D_CPU0_SA_DQS_DN<0>")
	)
	(segment
		(start 342.548718 -275.259546)
		(end 342.27516 -275.259546)
		(width 0.088646)
		(layer "In6.Cu")
		(net "M_D_CPU0_SA_DQS_DN<0>")
	)
	(segment
		(start 320.420238 -291.37864)
		(end 320.420238 -291.554662)
		(width 0.18288)
		(layer "In6.Cu")
		(net "M_D_CPU0_SA_DQS_DN<0>")
	)
	(segment
		(start 341.647272 -275.405088)
		(end 341.647018 -275.405088)
		(width 0.088646)
		(layer "In6.Cu")
		(net "M_D_CPU0_SA_DQS_DN<0>")
	)
	(segment
		(start 322.712334 -289.086544)
		(end 322.324222 -289.474656)
		(width 0.18288)
		(layer "In6.Cu")
		(net "M_D_CPU0_SA_DQS_DN<0>")
	)
	(segment
		(start 332.467966 -280.554176)
		(end 332.311756 -280.710386)
		(width 0.088646)
		(layer "In6.Cu")
		(net "M_D_CPU0_SA_DQS_DN<0>")
	)
	(segment
		(start 328.600308 -283.374592)
		(end 328.424286 -283.374592)
		(width 0.18288)
		(layer "In6.Cu")
		(net "M_D_CPU0_SA_DQS_DN<0>")
	)
	(segment
		(start 328.424286 -283.374592)
		(end 328.036174 -283.762704)
		(width 0.18288)
		(layer "In6.Cu")
		(net "M_D_CPU0_SA_DQS_DN<0>")
	)
	(segment
		(start 266.2555 -312.114946)
		(end 265.719052 -312.336942)
		(width 0.18288)
		(layer "In6.Cu")
		(net "M_D_CPU0_SA_DQS_DN<0>")
	)
	(segment
		(start 313.9059 -298.892468)
		(end 313.60872 -299.189648)
		(width 0.18288)
		(layer "In6.Cu")
		(net "M_D_CPU0_SA_DQS_DN<0>")
	)
	(segment
		(start 325.56831 -286.230568)
		(end 325.180198 -286.61868)
		(width 0.18288)
		(layer "In6.Cu")
		(net "M_D_CPU0_SA_DQS_DN<0>")
	)
	(segment
		(start 308.309772 -300.637194)
		(end 307.58384 -300.93793)
		(width 0.18288)
		(layer "In6.Cu")
		(net "M_D_CPU0_SA_DQS_DN<0>")
	)
	(segment
		(start 324.228206 -287.570672)
		(end 324.228206 -287.746694)
		(width 0.18288)
		(layer "In6.Cu")
		(net "M_D_CPU0_SA_DQS_DN<0>")
	)
	(segment
		(start 332.467966 -279.996646)
		(end 332.467966 -280.554176)
		(width 0.088646)
		(layer "In6.Cu")
		(net "M_D_CPU0_SA_DQS_DN<0>")
	)
	(segment
		(start 330.504292 -281.470608)
		(end 330.32827 -281.470608)
		(width 0.18288)
		(layer "In6.Cu")
		(net "M_D_CPU0_SA_DQS_DN<0>")
	)
	(segment
		(start 342.021922 -275.405342)
		(end 342.021668 -275.405088)
		(width 0.088646)
		(layer "In6.Cu")
		(net "M_D_CPU0_SA_DQS_DN<0>")
	)
	(segment
		(start 267.757656 -312.753756)
		(end 267.267944 -312.26379)
		(width 0.18288)
		(layer "In6.Cu")
		(net "M_D_CPU0_SA_DQS_DN<0>")
	)
	(segment
		(start 332.311756 -280.710386)
		(end 332.077568 -280.710386)
		(width 0.088646)
		(layer "In6.Cu")
		(net "M_D_CPU0_SA_DQS_DN<0>")
	)
	(segment
		(start 314.301124 -298.892468)
		(end 313.9059 -298.892468)
		(width 0.18288)
		(layer "In6.Cu")
		(net "M_D_CPU0_SA_DQS_DN<0>")
	)
	(segment
		(start 285.711138 -314.130182)
		(end 284.93339 -314.452254)
		(width 0.18288)
		(layer "In6.Cu")
		(net "M_D_CPU0_SA_DQS_DN<0>")
	)
	(segment
		(start 324.616318 -287.18256)
		(end 324.228206 -287.570672)
		(width 0.18288)
		(layer "In6.Cu")
		(net "M_D_CPU0_SA_DQS_DN<0>")
	)
	(segment
		(start 327.648316 -284.326584)
		(end 327.472294 -284.326584)
		(width 0.18288)
		(layer "In6.Cu")
		(net "M_D_CPU0_SA_DQS_DN<0>")
	)
	(arc
		(start 336.462878 -277.838408)
		(mid 336.186403 -277.771088)
		(end 335.912206 -277.847044)
		(width 0.088646)
		(layer "In6.Cu")
		(net "M_D_CPU0_SA_DQS_DN<0>")
	)
	(arc
		(start 339.767164 -275.405088)
		(mid 339.490605 -275.329345)
		(end 339.212428 -275.398992)
		(width 0.088646)
		(layer "In6.Cu")
		(net "M_D_CPU0_SA_DQS_DN<0>")
	)
	(arc
		(start 337.979512 -275.8948)
		(mid 337.931833 -276.0777)
		(end 337.80095 -276.214078)
		(width 0.088646)
		(layer "In6.Cu")
		(net "M_D_CPU0_SA_DQS_DN<0>")
	)
	(arc
		(start 341.647018 -275.405088)
		(mid 341.372789 -275.329163)
		(end 341.096346 -275.396452)
		(width 0.088646)
		(layer "In6.Cu")
		(net "M_D_CPU0_SA_DQS_DN<0>")
	)
	(arc
		(start 337.309968 -277.040086)
		(mid 337.111678 -277.246045)
		(end 337.039458 -277.522686)
		(width 0.088646)
		(layer "In6.Cu")
		(net "M_D_CPU0_SA_DQS_DN<0>")
	)
	(arc
		(start 335.523078 -277.838408)
		(mid 335.246603 -277.771088)
		(end 334.972406 -277.847044)
		(width 0.088646)
		(layer "In6.Cu")
		(net "M_D_CPU0_SA_DQS_DN<0>")
	)
	(arc
		(start 334.032606 -277.847044)
		(mid 333.971266 -277.888068)
		(end 333.915766 -277.936706)
		(width 0.088646)
		(layer "In6.Cu")
		(net "M_D_CPU0_SA_DQS_DN<0>")
	)
	(arc
		(start 337.039458 -277.522686)
		(mid 336.991779 -277.705586)
		(end 336.860896 -277.841964)
		(width 0.088646)
		(layer "In6.Cu")
		(net "M_D_CPU0_SA_DQS_DN<0>")
	)
	(arc
		(start 340.707218 -275.405088)
		(mid 340.430405 -275.329218)
		(end 340.151974 -275.398992)
		(width 0.088646)
		(layer "In6.Cu")
		(net "M_D_CPU0_SA_DQS_DN<0>")
	)
	(arc
		(start 340.14156 -275.405088)
		(mid 339.954362 -275.455231)
		(end 339.767164 -275.405088)
		(width 0.088646)
		(layer "In6.Cu")
		(net "M_D_CPU0_SA_DQS_DN<0>")
	)
	(arc
		(start 337.79206 -276.219158)
		(mid 337.587725 -276.421763)
		(end 337.509612 -276.69871)
		(width 0.088646)
		(layer "In6.Cu")
		(net "M_D_CPU0_SA_DQS_DN<0>")
	)
	(arc
		(start 336.852006 -277.847044)
		(mid 336.664808 -277.897187)
		(end 336.47761 -277.847044)
		(width 0.088646)
		(layer "In6.Cu")
		(net "M_D_CPU0_SA_DQS_DN<0>")
	)
	(arc
		(start 342.021668 -275.405088)
		(mid 341.83447 -275.455231)
		(end 341.647272 -275.405088)
		(width 0.088646)
		(layer "In6.Cu")
		(net "M_D_CPU0_SA_DQS_DN<0>")
	)
	(arc
		(start 338.26196 -275.405088)
		(mid 338.059674 -275.604069)
		(end 337.979512 -275.876258)
		(width 0.088646)
		(layer "In6.Cu")
		(net "M_D_CPU0_SA_DQS_DN<0>")
	)
	(arc
		(start 335.912206 -277.847044)
		(mid 335.725008 -277.897187)
		(end 335.53781 -277.847044)
		(width 0.088646)
		(layer "In6.Cu")
		(net "M_D_CPU0_SA_DQS_DN<0>")
	)
	(arc
		(start 334.972406 -277.847044)
		(mid 334.785208 -277.897187)
		(end 334.59801 -277.847044)
		(width 0.088646)
		(layer "In6.Cu")
		(net "M_D_CPU0_SA_DQS_DN<0>")
	)
	(arc
		(start 334.583278 -277.838408)
		(mid 334.306803 -277.771088)
		(end 334.032606 -277.847044)
		(width 0.088646)
		(layer "In6.Cu")
		(net "M_D_CPU0_SA_DQS_DN<0>")
	)
	(arc
		(start 342.703404 -275.218652)
		(mid 342.628719 -275.249157)
		(end 342.548718 -275.259546)
		(width 0.088646)
		(layer "In6.Cu")
		(net "M_D_CPU0_SA_DQS_DN<0>")
	)
	(arc
		(start 337.509612 -276.708616)
		(mid 337.461933 -276.891516)
		(end 337.33105 -277.027894)
		(width 0.088646)
		(layer "In6.Cu")
		(net "M_D_CPU0_SA_DQS_DN<0>")
	)
	(arc
		(start 338.827618 -275.405088)
		(mid 338.550805 -275.329218)
		(end 338.272374 -275.398992)
		(width 0.088646)
		(layer "In6.Cu")
		(net "M_D_CPU0_SA_DQS_DN<0>")
	)
	(arc
		(start 339.202014 -275.405088)
		(mid 339.014816 -275.455231)
		(end 338.827618 -275.405088)
		(width 0.088646)
		(layer "In6.Cu")
		(net "M_D_CPU0_SA_DQS_DN<0>")
	)
	(arc
		(start 341.081614 -275.405088)
		(mid 340.894416 -275.455231)
		(end 340.707218 -275.405088)
		(width 0.088646)
		(layer "In6.Cu")
		(net "M_D_CPU0_SA_DQS_DN<0>")
	)
	(segment
		(start 346.532962 -278.336248)
		(end 346.533216 -278.336502)
		(width 0.20066)
		(layer "F.Cu")
		(net "M_D_CPU0_SA_DQ<9>")
	)
	(segment
		(start 261.381494 -304.841656)
		(end 261.050786 -304.841656)
		(width 0.101854)
		(layer "F.Cu")
		(net "M_D_CPU0_SA_DQ<9>")
	)
	(segment
		(start 346.532962 -277.800562)
		(end 346.532962 -278.336248)
		(width 0.20066)
		(layer "F.Cu")
		(net "M_D_CPU0_SA_DQ<9>")
	)
	(segment
		(start 261.050786 -304.841656)
		(end 259.065268 -304.841656)
		(width 0.1016)
		(layer "F.Cu")
		(net "M_D_CPU0_SA_DQ<9>")
	)
	(segment
		(start 259.056378 -304.832766)
		(end 258.44754 -304.832766)
		(width 0.20066)
		(layer "F.Cu")
		(net "M_D_CPU0_SA_DQ<9>")
	)
	(segment
		(start 259.065268 -304.841656)
		(end 259.056378 -304.832766)
		(width 0.1016)
		(layer "F.Cu")
		(net "M_D_CPU0_SA_DQ<9>")
	)
	(segment
		(start 258.28498 -305.323494)
		(end 258.130548 -305.477926)
		(width 0.20066)
		(layer "F.Cu")
		(net "M_D_CPU0_SA_DQ<9>")
	)
	(segment
		(start 258.130548 -305.477926)
		(end 257.626104 -305.477926)
		(width 0.20066)
		(layer "F.Cu")
		(net "M_D_CPU0_SA_DQ<9>")
	)
	(segment
		(start 261.560056 -304.841656)
		(end 261.381494 -304.841656)
		(width 0.20066)
		(layer "F.Cu")
		(net "M_D_CPU0_SA_DQ<9>")
	)
	(segment
		(start 258.44754 -304.832766)
		(end 258.28498 -304.995326)
		(width 0.20066)
		(layer "F.Cu")
		(net "M_D_CPU0_SA_DQ<9>")
	)
	(segment
		(start 261.984998 -305.266598)
		(end 261.560056 -304.841656)
		(width 0.20066)
		(layer "F.Cu")
		(net "M_D_CPU0_SA_DQ<9>")
	)
	(segment
		(start 257.626104 -305.477926)
		(end 257.414776 -305.266598)
		(width 0.20066)
		(layer "F.Cu")
		(net "M_D_CPU0_SA_DQ<9>")
	)
	(segment
		(start 263.624314 -305.266598)
		(end 261.984998 -305.266598)
		(width 0.20066)
		(layer "F.Cu")
		(net "M_D_CPU0_SA_DQ<9>")
	)
	(segment
		(start 264.729214 -305.266598)
		(end 263.624314 -305.266598)
		(width 0.20066)
		(layer "F.Cu")
		(net "M_D_CPU0_SA_DQ<9>")
	)
	(segment
		(start 258.28498 -304.995326)
		(end 258.28498 -305.323494)
		(width 0.20066)
		(layer "F.Cu")
		(net "M_D_CPU0_SA_DQ<9>")
	)
	(segment
		(start 257.414776 -305.266598)
		(end 256.080514 -305.266598)
		(width 0.20066)
		(layer "F.Cu")
		(net "M_D_CPU0_SA_DQ<9>")
	)
	(segment
		(start 273.720052 -311.637426)
		(end 272.730722 -310.648096)
		(width 0.18288)
		(layer "In11.Cu")
		(net "M_D_CPU0_SA_DQ<9>")
	)
	(segment
		(start 333.940912 -279.964134)
		(end 333.940912 -279.982676)
		(width 0.088646)
		(layer "In11.Cu")
		(net "M_D_CPU0_SA_DQ<9>")
	)
	(segment
		(start 336.477864 -278.82596)
		(end 336.468974 -278.83104)
		(width 0.088646)
		(layer "In11.Cu")
		(net "M_D_CPU0_SA_DQ<9>")
	)
	(segment
		(start 344.936318 -278.82596)
		(end 344.936064 -278.82596)
		(width 0.088646)
		(layer "In11.Cu")
		(net "M_D_CPU0_SA_DQ<9>")
	)
	(segment
		(start 333.471012 -281.585416)
		(end 332.894432 -282.161996)
		(width 0.088646)
		(layer "In11.Cu")
		(net "M_D_CPU0_SA_DQ<9>")
	)
	(segment
		(start 303.600612 -308.133496)
		(end 302.791622 -308.942486)
		(width 0.18288)
		(layer "In11.Cu")
		(net "M_D_CPU0_SA_DQ<9>")
	)
	(segment
		(start 314.60567 -303.616106)
		(end 314.60567 -303.760886)
		(width 0.18288)
		(layer "In11.Cu")
		(net "M_D_CPU0_SA_DQ<9>")
	)
	(segment
		(start 314.60567 -303.760886)
		(end 314.373514 -303.993042)
		(width 0.18288)
		(layer "In11.Cu")
		(net "M_D_CPU0_SA_DQ<9>")
	)
	(segment
		(start 266.261088 -305.902614)
		(end 264.729214 -305.266598)
		(width 0.18288)
		(layer "In11.Cu")
		(net "M_D_CPU0_SA_DQ<9>")
	)
	(segment
		(start 288.915094 -311.739026)
		(end 287.83153 -310.655462)
		(width 0.18288)
		(layer "In11.Cu")
		(net "M_D_CPU0_SA_DQ<9>")
	)
	(segment
		(start 331.33411 -283.381196)
		(end 322.223384 -292.491922)
		(width 0.18288)
		(layer "In11.Cu")
		(net "M_D_CPU0_SA_DQ<9>")
	)
	(segment
		(start 276.554946 -311.637426)
		(end 273.720052 -311.637426)
		(width 0.18288)
		(layer "In11.Cu")
		(net "M_D_CPU0_SA_DQ<9>")
	)
	(segment
		(start 342.116918 -278.82596)
		(end 342.116664 -278.82596)
		(width 0.088646)
		(layer "In11.Cu")
		(net "M_D_CPU0_SA_DQ<9>")
	)
	(segment
		(start 314.373514 -303.993042)
		(end 313.711336 -303.993042)
		(width 0.18288)
		(layer "In11.Cu")
		(net "M_D_CPU0_SA_DQ<9>")
	)
	(segment
		(start 302.791622 -308.942486)
		(end 302.34001 -308.942486)
		(width 0.18288)
		(layer "In11.Cu")
		(net "M_D_CPU0_SA_DQ<9>")
	)
	(segment
		(start 308.724808 -304.840894)
		(end 308.066186 -305.499516)
		(width 0.18288)
		(layer "In11.Cu")
		(net "M_D_CPU0_SA_DQ<9>")
	)
	(segment
		(start 312.965338 -304.73904)
		(end 310.615838 -304.73904)
		(width 0.18288)
		(layer "In11.Cu")
		(net "M_D_CPU0_SA_DQ<9>")
	)
	(segment
		(start 304.593752 -308.133496)
		(end 303.600612 -308.133496)
		(width 0.18288)
		(layer "In11.Cu")
		(net "M_D_CPU0_SA_DQ<9>")
	)
	(segment
		(start 322.223384 -292.491922)
		(end 322.223384 -293.361872)
		(width 0.18288)
		(layer "In11.Cu")
		(net "M_D_CPU0_SA_DQ<9>")
	)
	(segment
		(start 269.519146 -305.691286)
		(end 267.992098 -305.691286)
		(width 0.18288)
		(layer "In11.Cu")
		(net "M_D_CPU0_SA_DQ<9>")
	)
	(segment
		(start 332.894432 -282.309062)
		(end 331.822298 -283.381196)
		(width 0.088646)
		(layer "In11.Cu")
		(net "M_D_CPU0_SA_DQ<9>")
	)
	(segment
		(start 318.391032 -299.830744)
		(end 314.60567 -303.616106)
		(width 0.18288)
		(layer "In11.Cu")
		(net "M_D_CPU0_SA_DQ<9>")
	)
	(segment
		(start 310.513984 -304.840894)
		(end 308.724808 -304.840894)
		(width 0.18288)
		(layer "In11.Cu")
		(net "M_D_CPU0_SA_DQ<9>")
	)
	(segment
		(start 334.128364 -279.639776)
		(end 334.119474 -279.644856)
		(width 0.088646)
		(layer "In11.Cu")
		(net "M_D_CPU0_SA_DQ<9>")
	)
	(segment
		(start 299.440092 -310.792114)
		(end 298.370244 -310.792114)
		(width 0.18288)
		(layer "In11.Cu")
		(net "M_D_CPU0_SA_DQ<9>")
	)
	(segment
		(start 294.270176 -311.641998)
		(end 294.173148 -311.739026)
		(width 0.18288)
		(layer "In11.Cu")
		(net "M_D_CPU0_SA_DQ<9>")
	)
	(segment
		(start 271.198594 -306.345082)
		(end 270.387318 -305.533806)
		(width 0.18288)
		(layer "In11.Cu")
		(net "M_D_CPU0_SA_DQ<9>")
	)
	(segment
		(start 278.65959 -312.19521)
		(end 277.11273 -312.19521)
		(width 0.18288)
		(layer "In11.Cu")
		(net "M_D_CPU0_SA_DQ<9>")
	)
	(segment
		(start 271.198594 -309.849774)
		(end 271.198594 -306.345082)
		(width 0.18288)
		(layer "In11.Cu")
		(net "M_D_CPU0_SA_DQ<9>")
	)
	(segment
		(start 270.387318 -305.533806)
		(end 269.676626 -305.533806)
		(width 0.18288)
		(layer "In11.Cu")
		(net "M_D_CPU0_SA_DQ<9>")
	)
	(segment
		(start 284.73781 -310.655462)
		(end 284.601158 -310.792114)
		(width 0.18288)
		(layer "In11.Cu")
		(net "M_D_CPU0_SA_DQ<9>")
	)
	(segment
		(start 341.176864 -278.82596)
		(end 341.162132 -278.834596)
		(width 0.088646)
		(layer "In11.Cu")
		(net "M_D_CPU0_SA_DQ<9>")
	)
	(segment
		(start 266.915646 -305.902614)
		(end 266.261088 -305.902614)
		(width 0.18288)
		(layer "In11.Cu")
		(net "M_D_CPU0_SA_DQ<9>")
	)
	(segment
		(start 277.11273 -312.19521)
		(end 276.554946 -311.637426)
		(width 0.18288)
		(layer "In11.Cu")
		(net "M_D_CPU0_SA_DQ<9>")
	)
	(segment
		(start 313.711336 -303.993042)
		(end 312.965338 -304.73904)
		(width 0.18288)
		(layer "In11.Cu")
		(net "M_D_CPU0_SA_DQ<9>")
	)
	(segment
		(start 343.056464 -278.82596)
		(end 343.04605 -278.832056)
		(width 0.088646)
		(layer "In11.Cu")
		(net "M_D_CPU0_SA_DQ<9>")
	)
	(segment
		(start 282.43276 -311.641998)
		(end 279.212802 -311.641998)
		(width 0.18288)
		(layer "In11.Cu")
		(net "M_D_CPU0_SA_DQ<9>")
	)
	(segment
		(start 300.612048 -310.670448)
		(end 299.561758 -310.670448)
		(width 0.18288)
		(layer "In11.Cu")
		(net "M_D_CPU0_SA_DQ<9>")
	)
	(segment
		(start 331.709522 -283.381196)
		(end 331.33411 -283.381196)
		(width 0.18288)
		(layer "In11.Cu")
		(net "M_D_CPU0_SA_DQ<9>")
	)
	(segment
		(start 332.894432 -282.161996)
		(end 332.894432 -282.309062)
		(width 0.088646)
		(layer "In11.Cu")
		(net "M_D_CPU0_SA_DQ<9>")
	)
	(segment
		(start 340.237064 -278.82596)
		(end 340.222332 -278.834596)
		(width 0.088646)
		(layer "In11.Cu")
		(net "M_D_CPU0_SA_DQ<9>")
	)
	(segment
		(start 284.601158 -310.792114)
		(end 283.282644 -310.792114)
		(width 0.18288)
		(layer "In11.Cu")
		(net "M_D_CPU0_SA_DQ<9>")
	)
	(segment
		(start 333.658464 -280.453846)
		(end 333.649574 -280.458926)
		(width 0.088646)
		(layer "In11.Cu")
		(net "M_D_CPU0_SA_DQ<9>")
	)
	(segment
		(start 310.615838 -304.73904)
		(end 310.513984 -304.840894)
		(width 0.18288)
		(layer "In11.Cu")
		(net "M_D_CPU0_SA_DQ<9>")
	)
	(segment
		(start 271.996916 -310.648096)
		(end 271.198594 -309.849774)
		(width 0.18288)
		(layer "In11.Cu")
		(net "M_D_CPU0_SA_DQ<9>")
	)
	(segment
		(start 345.876118 -278.82596)
		(end 345.875864 -278.82596)
		(width 0.088646)
		(layer "In11.Cu")
		(net "M_D_CPU0_SA_DQ<9>")
	)
	(segment
		(start 322.223384 -293.361872)
		(end 318.391032 -297.194224)
		(width 0.18288)
		(layer "In11.Cu")
		(net "M_D_CPU0_SA_DQ<9>")
	)
	(segment
		(start 298.370244 -310.792114)
		(end 297.52036 -311.641998)
		(width 0.18288)
		(layer "In11.Cu")
		(net "M_D_CPU0_SA_DQ<9>")
	)
	(segment
		(start 344.936064 -278.82596)
		(end 344.921332 -278.834596)
		(width 0.088646)
		(layer "In11.Cu")
		(net "M_D_CPU0_SA_DQ<9>")
	)
	(segment
		(start 318.391032 -297.194224)
		(end 318.391032 -299.830744)
		(width 0.18288)
		(layer "In11.Cu")
		(net "M_D_CPU0_SA_DQ<9>")
	)
	(segment
		(start 302.34001 -308.942486)
		(end 300.612048 -310.670448)
		(width 0.18288)
		(layer "In11.Cu")
		(net "M_D_CPU0_SA_DQ<9>")
	)
	(segment
		(start 287.83153 -310.655462)
		(end 284.73781 -310.655462)
		(width 0.18288)
		(layer "In11.Cu")
		(net "M_D_CPU0_SA_DQ<9>")
	)
	(segment
		(start 333.471012 -280.778204)
		(end 333.471012 -281.585416)
		(width 0.088646)
		(layer "In11.Cu")
		(net "M_D_CPU0_SA_DQ<9>")
	)
	(segment
		(start 283.282644 -310.792114)
		(end 282.43276 -311.641998)
		(width 0.18288)
		(layer "In11.Cu")
		(net "M_D_CPU0_SA_DQ<9>")
	)
	(segment
		(start 294.173148 -311.739026)
		(end 288.915094 -311.739026)
		(width 0.18288)
		(layer "In11.Cu")
		(net "M_D_CPU0_SA_DQ<9>")
	)
	(segment
		(start 336.290412 -279.150318)
		(end 336.290412 -279.160224)
		(width 0.088646)
		(layer "In11.Cu")
		(net "M_D_CPU0_SA_DQ<9>")
	)
	(segment
		(start 307.227732 -305.499516)
		(end 304.593752 -308.133496)
		(width 0.18288)
		(layer "In11.Cu")
		(net "M_D_CPU0_SA_DQ<9>")
	)
	(segment
		(start 272.730722 -310.648096)
		(end 271.996916 -310.648096)
		(width 0.18288)
		(layer "In11.Cu")
		(net "M_D_CPU0_SA_DQ<9>")
	)
	(segment
		(start 279.212802 -311.641998)
		(end 278.65959 -312.19521)
		(width 0.18288)
		(layer "In11.Cu")
		(net "M_D_CPU0_SA_DQ<9>")
	)
	(segment
		(start 267.992098 -305.691286)
		(end 266.915646 -305.902614)
		(width 0.18288)
		(layer "In11.Cu")
		(net "M_D_CPU0_SA_DQ<9>")
	)
	(segment
		(start 346.533216 -278.336502)
		(end 345.905328 -278.809196)
		(width 0.088646)
		(layer "In11.Cu")
		(net "M_D_CPU0_SA_DQ<9>")
	)
	(segment
		(start 343.996264 -278.82596)
		(end 343.981532 -278.834596)
		(width 0.088646)
		(layer "In11.Cu")
		(net "M_D_CPU0_SA_DQ<9>")
	)
	(segment
		(start 308.066186 -305.499516)
		(end 307.227732 -305.499516)
		(width 0.18288)
		(layer "In11.Cu")
		(net "M_D_CPU0_SA_DQ<9>")
	)
	(segment
		(start 297.52036 -311.641998)
		(end 294.270176 -311.641998)
		(width 0.18288)
		(layer "In11.Cu")
		(net "M_D_CPU0_SA_DQ<9>")
	)
	(segment
		(start 345.905328 -278.809196)
		(end 345.876118 -278.82596)
		(width 0.088646)
		(layer "In11.Cu")
		(net "M_D_CPU0_SA_DQ<9>")
	)
	(segment
		(start 299.561758 -310.670448)
		(end 299.440092 -310.792114)
		(width 0.18288)
		(layer "In11.Cu")
		(net "M_D_CPU0_SA_DQ<9>")
	)
	(segment
		(start 269.676626 -305.533806)
		(end 269.519146 -305.691286)
		(width 0.18288)
		(layer "In11.Cu")
		(net "M_D_CPU0_SA_DQ<9>")
	)
	(segment
		(start 331.822298 -283.381196)
		(end 331.709522 -283.381196)
		(width 0.088646)
		(layer "In11.Cu")
		(net "M_D_CPU0_SA_DQ<9>")
	)
	(arc
		(start 340.222332 -278.834596)
		(mid 339.945857 -278.901916)
		(end 339.67166 -278.82596)
		(width 0.088646)
		(layer "In11.Cu")
		(net "M_D_CPU0_SA_DQ<9>")
	)
	(arc
		(start 335.44256 -279.639776)
		(mid 335.255362 -279.589633)
		(end 335.068164 -279.639776)
		(width 0.088646)
		(layer "In11.Cu")
		(net "M_D_CPU0_SA_DQ<9>")
	)
	(arc
		(start 345.31046 -278.82596)
		(mid 345.123406 -278.77591)
		(end 344.936318 -278.82596)
		(width 0.088646)
		(layer "In11.Cu")
		(net "M_D_CPU0_SA_DQ<9>")
	)
	(arc
		(start 333.649574 -280.458926)
		(mid 333.51866 -280.595286)
		(end 333.471012 -280.778204)
		(width 0.088646)
		(layer "In11.Cu")
		(net "M_D_CPU0_SA_DQ<9>")
	)
	(arc
		(start 343.04605 -278.832056)
		(mid 342.767872 -278.901779)
		(end 342.491314 -278.82596)
		(width 0.088646)
		(layer "In11.Cu")
		(net "M_D_CPU0_SA_DQ<9>")
	)
	(arc
		(start 335.068164 -279.639776)
		(mid 334.785462 -279.715552)
		(end 334.50276 -279.639776)
		(width 0.088646)
		(layer "In11.Cu")
		(net "M_D_CPU0_SA_DQ<9>")
	)
	(arc
		(start 336.85226 -278.82596)
		(mid 336.665062 -278.775817)
		(end 336.477864 -278.82596)
		(width 0.088646)
		(layer "In11.Cu")
		(net "M_D_CPU0_SA_DQ<9>")
	)
	(arc
		(start 333.940912 -279.982676)
		(mid 333.86075 -280.254865)
		(end 333.658464 -280.453846)
		(width 0.088646)
		(layer "In11.Cu")
		(net "M_D_CPU0_SA_DQ<9>")
	)
	(arc
		(start 336.007964 -279.639776)
		(mid 335.725262 -279.715552)
		(end 335.44256 -279.639776)
		(width 0.088646)
		(layer "In11.Cu")
		(net "M_D_CPU0_SA_DQ<9>")
	)
	(arc
		(start 339.67166 -278.82596)
		(mid 339.484462 -278.775817)
		(end 339.297264 -278.82596)
		(width 0.088646)
		(layer "In11.Cu")
		(net "M_D_CPU0_SA_DQ<9>")
	)
	(arc
		(start 334.119474 -279.644856)
		(mid 333.98856 -279.781216)
		(end 333.940912 -279.964134)
		(width 0.088646)
		(layer "In11.Cu")
		(net "M_D_CPU0_SA_DQ<9>")
	)
	(arc
		(start 342.116664 -278.82596)
		(mid 341.833962 -278.901736)
		(end 341.55126 -278.82596)
		(width 0.088646)
		(layer "In11.Cu")
		(net "M_D_CPU0_SA_DQ<9>")
	)
	(arc
		(start 336.468974 -278.83104)
		(mid 336.33806 -278.9674)
		(end 336.290412 -279.150318)
		(width 0.088646)
		(layer "In11.Cu")
		(net "M_D_CPU0_SA_DQ<9>")
	)
	(arc
		(start 342.491314 -278.82596)
		(mid 342.304116 -278.775817)
		(end 342.116918 -278.82596)
		(width 0.088646)
		(layer "In11.Cu")
		(net "M_D_CPU0_SA_DQ<9>")
	)
	(arc
		(start 341.162132 -278.834596)
		(mid 340.885657 -278.901916)
		(end 340.61146 -278.82596)
		(width 0.088646)
		(layer "In11.Cu")
		(net "M_D_CPU0_SA_DQ<9>")
	)
	(arc
		(start 341.55126 -278.82596)
		(mid 341.364062 -278.775817)
		(end 341.176864 -278.82596)
		(width 0.088646)
		(layer "In11.Cu")
		(net "M_D_CPU0_SA_DQ<9>")
	)
	(arc
		(start 339.297264 -278.82596)
		(mid 339.014562 -278.901736)
		(end 338.73186 -278.82596)
		(width 0.088646)
		(layer "In11.Cu")
		(net "M_D_CPU0_SA_DQ<9>")
	)
	(arc
		(start 340.61146 -278.82596)
		(mid 340.424262 -278.775817)
		(end 340.237064 -278.82596)
		(width 0.088646)
		(layer "In11.Cu")
		(net "M_D_CPU0_SA_DQ<9>")
	)
	(arc
		(start 338.357464 -278.82596)
		(mid 338.074762 -278.901736)
		(end 337.79206 -278.82596)
		(width 0.088646)
		(layer "In11.Cu")
		(net "M_D_CPU0_SA_DQ<9>")
	)
	(arc
		(start 336.290412 -279.160224)
		(mid 336.212301 -279.437173)
		(end 336.007964 -279.639776)
		(width 0.088646)
		(layer "In11.Cu")
		(net "M_D_CPU0_SA_DQ<9>")
	)
	(arc
		(start 343.981532 -278.834596)
		(mid 343.705057 -278.901916)
		(end 343.43086 -278.82596)
		(width 0.088646)
		(layer "In11.Cu")
		(net "M_D_CPU0_SA_DQ<9>")
	)
	(arc
		(start 334.50276 -279.639776)
		(mid 334.315562 -279.589633)
		(end 334.128364 -279.639776)
		(width 0.088646)
		(layer "In11.Cu")
		(net "M_D_CPU0_SA_DQ<9>")
	)
	(arc
		(start 337.417664 -278.82596)
		(mid 337.134962 -278.901736)
		(end 336.85226 -278.82596)
		(width 0.088646)
		(layer "In11.Cu")
		(net "M_D_CPU0_SA_DQ<9>")
	)
	(arc
		(start 338.73186 -278.82596)
		(mid 338.544662 -278.775817)
		(end 338.357464 -278.82596)
		(width 0.088646)
		(layer "In11.Cu")
		(net "M_D_CPU0_SA_DQ<9>")
	)
	(arc
		(start 344.37066 -278.82596)
		(mid 344.183462 -278.775817)
		(end 343.996264 -278.82596)
		(width 0.088646)
		(layer "In11.Cu")
		(net "M_D_CPU0_SA_DQ<9>")
	)
	(arc
		(start 345.875864 -278.82596)
		(mid 345.593162 -278.901736)
		(end 345.31046 -278.82596)
		(width 0.088646)
		(layer "In11.Cu")
		(net "M_D_CPU0_SA_DQ<9>")
	)
	(arc
		(start 337.79206 -278.82596)
		(mid 337.604862 -278.775817)
		(end 337.417664 -278.82596)
		(width 0.088646)
		(layer "In11.Cu")
		(net "M_D_CPU0_SA_DQ<9>")
	)
	(arc
		(start 343.43086 -278.82596)
		(mid 343.243662 -278.775817)
		(end 343.056464 -278.82596)
		(width 0.088646)
		(layer "In11.Cu")
		(net "M_D_CPU0_SA_DQ<9>")
	)
	(arc
		(start 344.921332 -278.834596)
		(mid 344.644857 -278.901916)
		(end 344.37066 -278.82596)
		(width 0.088646)
		(layer "In11.Cu")
		(net "M_D_CPU0_SA_DQ<9>")
	)
	(segment
		(start 259.064506 -306.541678)
		(end 259.056378 -306.53355)
		(width 0.101854)
		(layer "F.Cu")
		(net "M_D_CPU0_SA_DQ<8>")
	)
	(segment
		(start 259.31241 -306.541678)
		(end 259.064506 -306.541678)
		(width 0.101854)
		(layer "F.Cu")
		(net "M_D_CPU0_SA_DQ<8>")
	)
	(segment
		(start 257.653536 -307.20538)
		(end 257.414776 -306.96662)
		(width 0.20066)
		(layer "F.Cu")
		(net "M_D_CPU0_SA_DQ<8>")
	)
	(segment
		(start 258.28498 -307.03266)
		(end 258.11226 -307.20538)
		(width 0.20066)
		(layer "F.Cu")
		(net "M_D_CPU0_SA_DQ<8>")
	)
	(segment
		(start 261.381494 -306.541678)
		(end 259.31241 -306.541678)
		(width 0.1016)
		(layer "F.Cu")
		(net "M_D_CPU0_SA_DQ<8>")
	)
	(segment
		(start 347.003116 -278.614378)
		(end 347.003116 -279.150064)
		(width 0.20066)
		(layer "F.Cu")
		(net "M_D_CPU0_SA_DQ<8>")
	)
	(segment
		(start 259.056378 -306.53355)
		(end 258.49453 -306.53355)
		(width 0.20066)
		(layer "F.Cu")
		(net "M_D_CPU0_SA_DQ<8>")
	)
	(segment
		(start 262.255254 -306.96662)
		(end 261.830312 -306.541678)
		(width 0.20066)
		(layer "F.Cu")
		(net "M_D_CPU0_SA_DQ<8>")
	)
	(segment
		(start 258.49453 -306.53355)
		(end 258.28498 -306.7431)
		(width 0.20066)
		(layer "F.Cu")
		(net "M_D_CPU0_SA_DQ<8>")
	)
	(segment
		(start 257.414776 -306.96662)
		(end 256.080514 -306.96662)
		(width 0.20066)
		(layer "F.Cu")
		(net "M_D_CPU0_SA_DQ<8>")
	)
	(segment
		(start 258.11226 -307.20538)
		(end 257.653536 -307.20538)
		(width 0.20066)
		(layer "F.Cu")
		(net "M_D_CPU0_SA_DQ<8>")
	)
	(segment
		(start 261.830312 -306.541678)
		(end 261.381494 -306.541678)
		(width 0.20066)
		(layer "F.Cu")
		(net "M_D_CPU0_SA_DQ<8>")
	)
	(segment
		(start 347.003116 -279.150064)
		(end 347.002862 -279.150318)
		(width 0.20066)
		(layer "F.Cu")
		(net "M_D_CPU0_SA_DQ<8>")
	)
	(segment
		(start 263.624314 -306.96662)
		(end 262.255254 -306.96662)
		(width 0.20066)
		(layer "F.Cu")
		(net "M_D_CPU0_SA_DQ<8>")
	)
	(segment
		(start 258.28498 -306.7431)
		(end 258.28498 -307.03266)
		(width 0.20066)
		(layer "F.Cu")
		(net "M_D_CPU0_SA_DQ<8>")
	)
	(segment
		(start 264.729214 -306.96662)
		(end 263.624314 -306.96662)
		(width 0.20066)
		(layer "F.Cu")
		(net "M_D_CPU0_SA_DQ<8>")
	)
	(segment
		(start 292.386512 -313.313826)
		(end 291.556694 -313.466226)
		(width 0.18288)
		(layer "In11.Cu")
		(net "M_D_CPU0_SA_DQ<8>")
	)
	(segment
		(start 334.128364 -281.267662)
		(end 334.119474 -281.272742)
		(width 0.088646)
		(layer "In11.Cu")
		(net "M_D_CPU0_SA_DQ<8>")
	)
	(segment
		(start 279.41397 -314.19165)
		(end 278.768556 -314.267596)
		(width 0.18288)
		(layer "In11.Cu")
		(net "M_D_CPU0_SA_DQ<8>")
	)
	(segment
		(start 333.373222 -282.673044)
		(end 332.188058 -283.858208)
		(width 0.088646)
		(layer "In11.Cu")
		(net "M_D_CPU0_SA_DQ<8>")
	)
	(segment
		(start 283.629354 -313.341766)
		(end 280.332434 -314.19165)
		(width 0.18288)
		(layer "In11.Cu")
		(net "M_D_CPU0_SA_DQ<8>")
	)
	(segment
		(start 296.003472 -313.604148)
		(end 296.003472 -313.976004)
		(width 0.18288)
		(layer "In11.Cu")
		(net "M_D_CPU0_SA_DQ<8>")
	)
	(segment
		(start 293.314628 -313.313826)
		(end 292.386512 -313.313826)
		(width 0.18288)
		(layer "In11.Cu")
		(net "M_D_CPU0_SA_DQ<8>")
	)
	(segment
		(start 280.332434 -314.19165)
		(end 279.41397 -314.19165)
		(width 0.18288)
		(layer "In11.Cu")
		(net "M_D_CPU0_SA_DQ<8>")
	)
	(segment
		(start 265.813794 -308.0512)
		(end 264.729214 -306.96662)
		(width 0.18288)
		(layer "In11.Cu")
		(net "M_D_CPU0_SA_DQ<8>")
	)
	(segment
		(start 269.147036 -309.09133)
		(end 268.467078 -309.09133)
		(width 0.18288)
		(layer "In11.Cu")
		(net "M_D_CPU0_SA_DQ<8>")
	)
	(segment
		(start 319.442338 -300.536864)
		(end 314.287154 -305.692048)
		(width 0.18288)
		(layer "In11.Cu")
		(net "M_D_CPU0_SA_DQ<8>")
	)
	(segment
		(start 296.704512 -313.986672)
		(end 296.704512 -313.604148)
		(width 0.18288)
		(layer "In11.Cu")
		(net "M_D_CPU0_SA_DQ<8>")
	)
	(segment
		(start 298.753276 -313.342274)
		(end 297.915838 -314.179712)
		(width 0.18288)
		(layer "In11.Cu")
		(net "M_D_CPU0_SA_DQ<8>")
	)
	(segment
		(start 289.423094 -313.466226)
		(end 288.203894 -313.263026)
		(width 0.18288)
		(layer "In11.Cu")
		(net "M_D_CPU0_SA_DQ<8>")
	)
	(segment
		(start 341.092028 -279.645872)
		(end 341.081614 -279.639776)
		(width 0.088646)
		(layer "In11.Cu")
		(net "M_D_CPU0_SA_DQ<8>")
	)
	(segment
		(start 332.188058 -283.858208)
		(end 332.188058 -283.964888)
		(width 0.088646)
		(layer "In11.Cu")
		(net "M_D_CPU0_SA_DQ<8>")
	)
	(segment
		(start 308.048914 -307.276246)
		(end 307.678074 -307.276246)
		(width 0.18288)
		(layer "In11.Cu")
		(net "M_D_CPU0_SA_DQ<8>")
	)
	(segment
		(start 297.915838 -314.179712)
		(end 296.897552 -314.179712)
		(width 0.18288)
		(layer "In11.Cu")
		(net "M_D_CPU0_SA_DQ<8>")
	)
	(segment
		(start 299.788326 -313.342274)
		(end 298.753276 -313.342274)
		(width 0.18288)
		(layer "In11.Cu")
		(net "M_D_CPU0_SA_DQ<8>")
	)
	(segment
		(start 294.195754 -314.194952)
		(end 293.314628 -313.313826)
		(width 0.18288)
		(layer "In11.Cu")
		(net "M_D_CPU0_SA_DQ<8>")
	)
	(segment
		(start 288.203894 -313.263026)
		(end 286.928814 -313.263026)
		(width 0.18288)
		(layer "In11.Cu")
		(net "M_D_CPU0_SA_DQ<8>")
	)
	(segment
		(start 334.410812 -280.778204)
		(end 334.410812 -280.78811)
		(width 0.088646)
		(layer "In11.Cu")
		(net "M_D_CPU0_SA_DQ<8>")
	)
	(segment
		(start 267.426948 -308.0512)
		(end 265.813794 -308.0512)
		(width 0.18288)
		(layer "In11.Cu")
		(net "M_D_CPU0_SA_DQ<8>")
	)
	(segment
		(start 268.467078 -309.09133)
		(end 267.426948 -308.0512)
		(width 0.18288)
		(layer "In11.Cu")
		(net "M_D_CPU0_SA_DQ<8>")
	)
	(segment
		(start 319.442338 -297.71467)
		(end 319.442338 -300.536864)
		(width 0.18288)
		(layer "In11.Cu")
		(net "M_D_CPU0_SA_DQ<8>")
	)
	(segment
		(start 312.973974 -306.379118)
		(end 310.590438 -306.379118)
		(width 0.18288)
		(layer "In11.Cu")
		(net "M_D_CPU0_SA_DQ<8>")
	)
	(segment
		(start 306.949094 -308.005226)
		(end 306.174394 -308.271926)
		(width 0.18288)
		(layer "In11.Cu")
		(net "M_D_CPU0_SA_DQ<8>")
	)
	(segment
		(start 285.477458 -313.125358)
		(end 284.602174 -313.168284)
		(width 0.18288)
		(layer "In11.Cu")
		(net "M_D_CPU0_SA_DQ<8>")
	)
	(segment
		(start 333.940912 -281.59202)
		(end 333.940912 -281.746198)
		(width 0.088646)
		(layer "In11.Cu")
		(net "M_D_CPU0_SA_DQ<8>")
	)
	(segment
		(start 310.590438 -306.379118)
		(end 310.427116 -306.54244)
		(width 0.18288)
		(layer "In11.Cu")
		(net "M_D_CPU0_SA_DQ<8>")
	)
	(segment
		(start 323.239384 -293.917624)
		(end 319.442338 -297.71467)
		(width 0.18288)
		(layer "In11.Cu")
		(net "M_D_CPU0_SA_DQ<8>")
	)
	(segment
		(start 334.598264 -280.453846)
		(end 334.589374 -280.458926)
		(width 0.088646)
		(layer "In11.Cu")
		(net "M_D_CPU0_SA_DQ<8>")
	)
	(segment
		(start 323.239384 -292.913562)
		(end 323.239384 -293.917624)
		(width 0.18288)
		(layer "In11.Cu")
		(net "M_D_CPU0_SA_DQ<8>")
	)
	(segment
		(start 307.678074 -307.276246)
		(end 306.949094 -308.005226)
		(width 0.18288)
		(layer "In11.Cu")
		(net "M_D_CPU0_SA_DQ<8>")
	)
	(segment
		(start 306.174394 -308.271926)
		(end 304.85715 -309.58917)
		(width 0.18288)
		(layer "In11.Cu")
		(net "M_D_CPU0_SA_DQ<8>")
	)
	(segment
		(start 286.928814 -313.263026)
		(end 285.477458 -313.125358)
		(width 0.18288)
		(layer "In11.Cu")
		(net "M_D_CPU0_SA_DQ<8>")
	)
	(segment
		(start 336.947764 -279.639776)
		(end 336.938874 -279.644856)
		(width 0.088646)
		(layer "In11.Cu")
		(net "M_D_CPU0_SA_DQ<8>")
	)
	(segment
		(start 304.85715 -309.58917)
		(end 303.181512 -310.283352)
		(width 0.18288)
		(layer "In11.Cu")
		(net "M_D_CPU0_SA_DQ<8>")
	)
	(segment
		(start 314.287154 -305.692048)
		(end 313.661044 -305.692048)
		(width 0.18288)
		(layer "In11.Cu")
		(net "M_D_CPU0_SA_DQ<8>")
	)
	(segment
		(start 296.704512 -313.604148)
		(end 296.511472 -313.411108)
		(width 0.18288)
		(layer "In11.Cu")
		(net "M_D_CPU0_SA_DQ<8>")
	)
	(segment
		(start 336.760312 -279.964134)
		(end 336.760312 -279.982676)
		(width 0.088646)
		(layer "In11.Cu")
		(net "M_D_CPU0_SA_DQ<8>")
	)
	(segment
		(start 296.897552 -314.179712)
		(end 296.704512 -313.986672)
		(width 0.18288)
		(layer "In11.Cu")
		(net "M_D_CPU0_SA_DQ<8>")
	)
	(segment
		(start 296.196512 -313.411108)
		(end 296.003472 -313.604148)
		(width 0.18288)
		(layer "In11.Cu")
		(net "M_D_CPU0_SA_DQ<8>")
	)
	(segment
		(start 278.768556 -314.267596)
		(end 277.440644 -314.216542)
		(width 0.18288)
		(layer "In11.Cu")
		(net "M_D_CPU0_SA_DQ<8>")
	)
	(segment
		(start 338.272374 -279.645872)
		(end 338.26196 -279.639776)
		(width 0.088646)
		(layer "In11.Cu")
		(net "M_D_CPU0_SA_DQ<8>")
	)
	(segment
		(start 291.556694 -313.466226)
		(end 289.423094 -313.466226)
		(width 0.18288)
		(layer "In11.Cu")
		(net "M_D_CPU0_SA_DQ<8>")
	)
	(segment
		(start 272.90141 -313.265312)
		(end 269.456154 -309.820056)
		(width 0.18288)
		(layer "In11.Cu")
		(net "M_D_CPU0_SA_DQ<8>")
	)
	(segment
		(start 302.346614 -310.783986)
		(end 299.788326 -313.342274)
		(width 0.18288)
		(layer "In11.Cu")
		(net "M_D_CPU0_SA_DQ<8>")
	)
	(segment
		(start 284.602174 -313.168284)
		(end 284.57144 -313.18073)
		(width 0.18288)
		(layer "In11.Cu")
		(net "M_D_CPU0_SA_DQ<8>")
	)
	(segment
		(start 308.78272 -306.54244)
		(end 308.048914 -307.276246)
		(width 0.18288)
		(layer "In11.Cu")
		(net "M_D_CPU0_SA_DQ<8>")
	)
	(segment
		(start 339.216746 -279.648412)
		(end 339.202014 -279.639776)
		(width 0.088646)
		(layer "In11.Cu")
		(net "M_D_CPU0_SA_DQ<8>")
	)
	(segment
		(start 296.511472 -313.411108)
		(end 296.196512 -313.411108)
		(width 0.18288)
		(layer "In11.Cu")
		(net "M_D_CPU0_SA_DQ<8>")
	)
	(segment
		(start 346.587318 -279.379426)
		(end 346.541598 -279.451816)
		(width 0.088646)
		(layer "In11.Cu")
		(net "M_D_CPU0_SA_DQ<8>")
	)
	(segment
		(start 313.661044 -305.692048)
		(end 312.973974 -306.379118)
		(width 0.18288)
		(layer "In11.Cu")
		(net "M_D_CPU0_SA_DQ<8>")
	)
	(segment
		(start 342.586564 -279.639776)
		(end 342.571832 -279.648412)
		(width 0.088646)
		(layer "In11.Cu")
		(net "M_D_CPU0_SA_DQ<8>")
	)
	(segment
		(start 333.940912 -281.746198)
		(end 333.373222 -282.313888)
		(width 0.088646)
		(layer "In11.Cu")
		(net "M_D_CPU0_SA_DQ<8>")
	)
	(segment
		(start 296.003472 -313.976004)
		(end 295.784524 -314.194952)
		(width 0.18288)
		(layer "In11.Cu")
		(net "M_D_CPU0_SA_DQ<8>")
	)
	(segment
		(start 269.456154 -309.820056)
		(end 269.456154 -309.400448)
		(width 0.18288)
		(layer "In11.Cu")
		(net "M_D_CPU0_SA_DQ<8>")
	)
	(segment
		(start 331.701394 -284.451552)
		(end 323.239384 -292.913562)
		(width 0.18288)
		(layer "In11.Cu")
		(net "M_D_CPU0_SA_DQ<8>")
	)
	(segment
		(start 342.971374 -279.645872)
		(end 342.96096 -279.639776)
		(width 0.088646)
		(layer "In11.Cu")
		(net "M_D_CPU0_SA_DQ<8>")
	)
	(segment
		(start 284.57144 -313.18073)
		(end 284.327854 -313.341766)
		(width 0.18288)
		(layer "In11.Cu")
		(net "M_D_CPU0_SA_DQ<8>")
	)
	(segment
		(start 295.784524 -314.194952)
		(end 294.195754 -314.194952)
		(width 0.18288)
		(layer "In11.Cu")
		(net "M_D_CPU0_SA_DQ<8>")
	)
	(segment
		(start 332.188058 -283.964888)
		(end 331.701394 -284.451552)
		(width 0.088646)
		(layer "In11.Cu")
		(net "M_D_CPU0_SA_DQ<8>")
	)
	(segment
		(start 333.373222 -282.313888)
		(end 333.373222 -282.673044)
		(width 0.088646)
		(layer "In11.Cu")
		(net "M_D_CPU0_SA_DQ<8>")
	)
	(segment
		(start 277.440644 -314.216542)
		(end 272.90141 -313.265312)
		(width 0.18288)
		(layer "In11.Cu")
		(net "M_D_CPU0_SA_DQ<8>")
	)
	(segment
		(start 340.156546 -279.648412)
		(end 340.141814 -279.639776)
		(width 0.088646)
		(layer "In11.Cu")
		(net "M_D_CPU0_SA_DQ<8>")
	)
	(segment
		(start 302.84801 -310.616854)
		(end 302.346614 -310.783986)
		(width 0.18288)
		(layer "In11.Cu")
		(net "M_D_CPU0_SA_DQ<8>")
	)
	(segment
		(start 303.181512 -310.283352)
		(end 302.84801 -310.616854)
		(width 0.18288)
		(layer "In11.Cu")
		(net "M_D_CPU0_SA_DQ<8>")
	)
	(segment
		(start 269.456154 -309.400448)
		(end 269.147036 -309.09133)
		(width 0.18288)
		(layer "In11.Cu")
		(net "M_D_CPU0_SA_DQ<8>")
	)
	(segment
		(start 343.915746 -279.648412)
		(end 343.901014 -279.639776)
		(width 0.088646)
		(layer "In11.Cu")
		(net "M_D_CPU0_SA_DQ<8>")
	)
	(segment
		(start 284.327854 -313.341766)
		(end 283.629354 -313.341766)
		(width 0.18288)
		(layer "In11.Cu")
		(net "M_D_CPU0_SA_DQ<8>")
	)
	(segment
		(start 344.855546 -279.648412)
		(end 344.840814 -279.639776)
		(width 0.088646)
		(layer "In11.Cu")
		(net "M_D_CPU0_SA_DQ<8>")
	)
	(segment
		(start 310.427116 -306.54244)
		(end 308.78272 -306.54244)
		(width 0.18288)
		(layer "In11.Cu")
		(net "M_D_CPU0_SA_DQ<8>")
	)
	(arc
		(start 346.346018 -279.639776)
		(mid 346.063316 -279.715552)
		(end 345.780614 -279.639776)
		(width 0.088646)
		(layer "In11.Cu")
		(net "M_D_CPU0_SA_DQ<8>")
	)
	(arc
		(start 346.541598 -279.451816)
		(mid 346.455241 -279.55769)
		(end 346.346018 -279.639776)
		(width 0.088646)
		(layer "In11.Cu")
		(net "M_D_CPU0_SA_DQ<8>")
	)
	(arc
		(start 341.646764 -279.639776)
		(mid 341.370205 -279.715519)
		(end 341.092028 -279.645872)
		(width 0.088646)
		(layer "In11.Cu")
		(net "M_D_CPU0_SA_DQ<8>")
	)
	(arc
		(start 342.571832 -279.648412)
		(mid 342.295357 -279.715732)
		(end 342.02116 -279.639776)
		(width 0.088646)
		(layer "In11.Cu")
		(net "M_D_CPU0_SA_DQ<8>")
	)
	(arc
		(start 340.707218 -279.639776)
		(mid 340.433019 -279.715611)
		(end 340.156546 -279.648412)
		(width 0.088646)
		(layer "In11.Cu")
		(net "M_D_CPU0_SA_DQ<8>")
	)
	(arc
		(start 344.840814 -279.639776)
		(mid 344.653616 -279.589633)
		(end 344.466418 -279.639776)
		(width 0.088646)
		(layer "In11.Cu")
		(net "M_D_CPU0_SA_DQ<8>")
	)
	(arc
		(start 345.406218 -279.639776)
		(mid 345.132019 -279.715611)
		(end 344.855546 -279.648412)
		(width 0.088646)
		(layer "In11.Cu")
		(net "M_D_CPU0_SA_DQ<8>")
	)
	(arc
		(start 334.97266 -280.453846)
		(mid 334.785462 -280.403703)
		(end 334.598264 -280.453846)
		(width 0.088646)
		(layer "In11.Cu")
		(net "M_D_CPU0_SA_DQ<8>")
	)
	(arc
		(start 334.410812 -280.78811)
		(mid 334.332701 -281.065059)
		(end 334.128364 -281.267662)
		(width 0.088646)
		(layer "In11.Cu")
		(net "M_D_CPU0_SA_DQ<8>")
	)
	(arc
		(start 339.202014 -279.639776)
		(mid 339.014816 -279.589633)
		(end 338.827618 -279.639776)
		(width 0.088646)
		(layer "In11.Cu")
		(net "M_D_CPU0_SA_DQ<8>")
	)
	(arc
		(start 347.002862 -279.150318)
		(mid 346.765593 -279.211383)
		(end 346.587318 -279.379426)
		(width 0.088646)
		(layer "In11.Cu")
		(net "M_D_CPU0_SA_DQ<8>")
	)
	(arc
		(start 345.780614 -279.639776)
		(mid 345.593416 -279.589633)
		(end 345.406218 -279.639776)
		(width 0.088646)
		(layer "In11.Cu")
		(net "M_D_CPU0_SA_DQ<8>")
	)
	(arc
		(start 343.526618 -279.639776)
		(mid 343.249805 -279.715646)
		(end 342.971374 -279.645872)
		(width 0.088646)
		(layer "In11.Cu")
		(net "M_D_CPU0_SA_DQ<8>")
	)
	(arc
		(start 336.477864 -280.453846)
		(mid 336.195162 -280.529588)
		(end 335.91246 -280.453846)
		(width 0.088646)
		(layer "In11.Cu")
		(net "M_D_CPU0_SA_DQ<8>")
	)
	(arc
		(start 336.938874 -279.644856)
		(mid 336.80796 -279.781216)
		(end 336.760312 -279.964134)
		(width 0.088646)
		(layer "In11.Cu")
		(net "M_D_CPU0_SA_DQ<8>")
	)
	(arc
		(start 338.827618 -279.639776)
		(mid 338.550805 -279.715646)
		(end 338.272374 -279.645872)
		(width 0.088646)
		(layer "In11.Cu")
		(net "M_D_CPU0_SA_DQ<8>")
	)
	(arc
		(start 337.887564 -279.639776)
		(mid 337.604862 -279.715552)
		(end 337.32216 -279.639776)
		(width 0.088646)
		(layer "In11.Cu")
		(net "M_D_CPU0_SA_DQ<8>")
	)
	(arc
		(start 342.02116 -279.639776)
		(mid 341.833962 -279.589633)
		(end 341.646764 -279.639776)
		(width 0.088646)
		(layer "In11.Cu")
		(net "M_D_CPU0_SA_DQ<8>")
	)
	(arc
		(start 343.901014 -279.639776)
		(mid 343.713816 -279.589633)
		(end 343.526618 -279.639776)
		(width 0.088646)
		(layer "In11.Cu")
		(net "M_D_CPU0_SA_DQ<8>")
	)
	(arc
		(start 334.119474 -281.272742)
		(mid 333.98856 -281.409102)
		(end 333.940912 -281.59202)
		(width 0.088646)
		(layer "In11.Cu")
		(net "M_D_CPU0_SA_DQ<8>")
	)
	(arc
		(start 342.96096 -279.639776)
		(mid 342.773762 -279.589633)
		(end 342.586564 -279.639776)
		(width 0.088646)
		(layer "In11.Cu")
		(net "M_D_CPU0_SA_DQ<8>")
	)
	(arc
		(start 336.760312 -279.982676)
		(mid 336.68015 -280.254865)
		(end 336.477864 -280.453846)
		(width 0.088646)
		(layer "In11.Cu")
		(net "M_D_CPU0_SA_DQ<8>")
	)
	(arc
		(start 335.538064 -280.453846)
		(mid 335.255362 -280.529588)
		(end 334.97266 -280.453846)
		(width 0.088646)
		(layer "In11.Cu")
		(net "M_D_CPU0_SA_DQ<8>")
	)
	(arc
		(start 335.91246 -280.453846)
		(mid 335.725262 -280.403703)
		(end 335.538064 -280.453846)
		(width 0.088646)
		(layer "In11.Cu")
		(net "M_D_CPU0_SA_DQ<8>")
	)
	(arc
		(start 339.767418 -279.639776)
		(mid 339.493219 -279.715611)
		(end 339.216746 -279.648412)
		(width 0.088646)
		(layer "In11.Cu")
		(net "M_D_CPU0_SA_DQ<8>")
	)
	(arc
		(start 338.26196 -279.639776)
		(mid 338.074762 -279.589633)
		(end 337.887564 -279.639776)
		(width 0.088646)
		(layer "In11.Cu")
		(net "M_D_CPU0_SA_DQ<8>")
	)
	(arc
		(start 341.081614 -279.639776)
		(mid 340.894416 -279.589633)
		(end 340.707218 -279.639776)
		(width 0.088646)
		(layer "In11.Cu")
		(net "M_D_CPU0_SA_DQ<8>")
	)
	(arc
		(start 344.466418 -279.639776)
		(mid 344.192219 -279.715611)
		(end 343.915746 -279.648412)
		(width 0.088646)
		(layer "In11.Cu")
		(net "M_D_CPU0_SA_DQ<8>")
	)
	(arc
		(start 337.32216 -279.639776)
		(mid 337.134962 -279.589633)
		(end 336.947764 -279.639776)
		(width 0.088646)
		(layer "In11.Cu")
		(net "M_D_CPU0_SA_DQ<8>")
	)
	(arc
		(start 340.141814 -279.639776)
		(mid 339.954616 -279.589633)
		(end 339.767418 -279.639776)
		(width 0.088646)
		(layer "In11.Cu")
		(net "M_D_CPU0_SA_DQ<8>")
	)
	(arc
		(start 334.589374 -280.458926)
		(mid 334.45846 -280.595286)
		(end 334.410812 -280.778204)
		(width 0.088646)
		(layer "In11.Cu")
		(net "M_D_CPU0_SA_DQ<8>")
	)
	(segment
		(start 265.518646 -308.092602)
		(end 265.369548 -308.2417)
		(width 0.20066)
		(layer "F.Cu")
		(net "M_D_CPU0_SA_DQ<7>")
	)
	(segment
		(start 266.25423 -308.024276)
		(end 266.042394 -307.81244)
		(width 0.20066)
		(layer "F.Cu")
		(net "M_D_CPU0_SA_DQ<7>")
	)
	(segment
		(start 262.146288 -308.255924)
		(end 262.003794 -308.11343)
		(width 0.20066)
		(layer "F.Cu")
		(net "M_D_CPU0_SA_DQ<7>")
	)
	(segment
		(start 265.369548 -308.2417)
		(end 264.825226 -308.2417)
		(width 0.20066)
		(layer "F.Cu")
		(net "M_D_CPU0_SA_DQ<7>")
	)
	(segment
		(start 266.700762 -308.024276)
		(end 266.25423 -308.024276)
		(width 0.20066)
		(layer "F.Cu")
		(net "M_D_CPU0_SA_DQ<7>")
	)
	(segment
		(start 261.87781 -307.816758)
		(end 260.180582 -307.816758)
		(width 0.20066)
		(layer "F.Cu")
		(net "M_D_CPU0_SA_DQ<7>")
	)
	(segment
		(start 265.518646 -307.940964)
		(end 265.518646 -308.092602)
		(width 0.20066)
		(layer "F.Cu")
		(net "M_D_CPU0_SA_DQ<7>")
	)
	(segment
		(start 265.64717 -307.81244)
		(end 265.518646 -307.940964)
		(width 0.20066)
		(layer "F.Cu")
		(net "M_D_CPU0_SA_DQ<7>")
	)
	(segment
		(start 266.042394 -307.81244)
		(end 265.64717 -307.81244)
		(width 0.20066)
		(layer "F.Cu")
		(net "M_D_CPU0_SA_DQ<7>")
	)
	(segment
		(start 262.752332 -308.2417)
		(end 262.514334 -308.2417)
		(width 0.101854)
		(layer "F.Cu")
		(net "M_D_CPU0_SA_DQ<7>")
	)
	(segment
		(start 262.003794 -307.942742)
		(end 261.87781 -307.816758)
		(width 0.20066)
		(layer "F.Cu")
		(net "M_D_CPU0_SA_DQ<7>")
	)
	(segment
		(start 264.825226 -308.2417)
		(end 262.752332 -308.2417)
		(width 0.1016)
		(layer "F.Cu")
		(net "M_D_CPU0_SA_DQ<7>")
	)
	(segment
		(start 266.90828 -307.816758)
		(end 266.700762 -308.024276)
		(width 0.20066)
		(layer "F.Cu")
		(net "M_D_CPU0_SA_DQ<7>")
	)
	(segment
		(start 267.724382 -307.816758)
		(end 266.90828 -307.816758)
		(width 0.20066)
		(layer "F.Cu")
		(net "M_D_CPU0_SA_DQ<7>")
	)
	(segment
		(start 262.003794 -308.11343)
		(end 262.003794 -307.942742)
		(width 0.20066)
		(layer "F.Cu")
		(net "M_D_CPU0_SA_DQ<7>")
	)
	(segment
		(start 262.50011 -308.255924)
		(end 262.146288 -308.255924)
		(width 0.20066)
		(layer "F.Cu")
		(net "M_D_CPU0_SA_DQ<7>")
	)
	(segment
		(start 262.514334 -308.2417)
		(end 262.50011 -308.255924)
		(width 0.101854)
		(layer "F.Cu")
		(net "M_D_CPU0_SA_DQ<7>")
	)
	(segment
		(start 268.829282 -307.816758)
		(end 267.724382 -307.816758)
		(width 0.20066)
		(layer "F.Cu")
		(net "M_D_CPU0_SA_DQ<7>")
	)
	(arc
		(start 344.653362 -272.917158)
		(mid 344.653425 -273.185128)
		(end 344.653616 -273.453098)
		(width 0.20066)
		(layer "F.Cu")
		(net "M_D_CPU0_SA_DQ<7>")
	)
	(segment
		(start 274.940014 -307.208428)
		(end 274.757134 -307.391308)
		(width 0.18288)
		(layer "In6.Cu")
		(net "M_D_CPU0_SA_DQ<7>")
	)
	(segment
		(start 344.653616 -273.453098)
		(end 344.340942 -273.453098)
		(width 0.088646)
		(layer "In6.Cu")
		(net "M_D_CPU0_SA_DQ<7>")
	)
	(segment
		(start 301.800768 -299.843952)
		(end 301.800768 -300.102524)
		(width 0.18288)
		(layer "In6.Cu")
		(net "M_D_CPU0_SA_DQ<7>")
	)
	(segment
		(start 270.93799 -307.391308)
		(end 270.77797 -307.231288)
		(width 0.18288)
		(layer "In6.Cu")
		(net "M_D_CPU0_SA_DQ<7>")
	)
	(segment
		(start 307.601874 -295.533318)
		(end 306.640738 -296.494454)
		(width 0.18288)
		(layer "In6.Cu")
		(net "M_D_CPU0_SA_DQ<7>")
	)
	(segment
		(start 293.40302 -304.952908)
		(end 292.441376 -304.952908)
		(width 0.18288)
		(layer "In6.Cu")
		(net "M_D_CPU0_SA_DQ<7>")
	)
	(segment
		(start 289.415474 -307.45811)
		(end 288.92119 -307.45811)
		(width 0.18288)
		(layer "In6.Cu")
		(net "M_D_CPU0_SA_DQ<7>")
	)
	(segment
		(start 277.345648 -306.814982)
		(end 277.345648 -307.208428)
		(width 0.18288)
		(layer "In6.Cu")
		(net "M_D_CPU0_SA_DQ<7>")
	)
	(segment
		(start 269.254732 -307.391308)
		(end 268.829282 -307.816758)
		(width 0.18288)
		(layer "In6.Cu")
		(net "M_D_CPU0_SA_DQ<7>")
	)
	(segment
		(start 280.573734 -307.39334)
		(end 278.224996 -307.39334)
		(width 0.18288)
		(layer "In6.Cu")
		(net "M_D_CPU0_SA_DQ<7>")
	)
	(segment
		(start 291.034978 -305.838606)
		(end 289.415474 -307.45811)
		(width 0.18288)
		(layer "In6.Cu")
		(net "M_D_CPU0_SA_DQ<7>")
	)
	(segment
		(start 294.364156 -303.991772)
		(end 293.40302 -304.952908)
		(width 0.18288)
		(layer "In6.Cu")
		(net "M_D_CPU0_SA_DQ<7>")
	)
	(segment
		(start 302.548036 -299.355256)
		(end 302.289464 -299.355256)
		(width 0.18288)
		(layer "In6.Cu")
		(net "M_D_CPU0_SA_DQ<7>")
	)
	(segment
		(start 328.222864 -278.446738)
		(end 314.119006 -292.550596)
		(width 0.18288)
		(layer "In6.Cu")
		(net "M_D_CPU0_SA_DQ<7>")
	)
	(segment
		(start 274.757134 -307.391308)
		(end 273.71167 -307.391308)
		(width 0.18288)
		(layer "In6.Cu")
		(net "M_D_CPU0_SA_DQ<7>")
	)
	(segment
		(start 336.39125 -273.772376)
		(end 336.38236 -273.777456)
		(width 0.088646)
		(layer "In6.Cu")
		(net "M_D_CPU0_SA_DQ<7>")
	)
	(segment
		(start 269.92453 -307.391308)
		(end 269.254732 -307.391308)
		(width 0.18288)
		(layer "In6.Cu")
		(net "M_D_CPU0_SA_DQ<7>")
	)
	(segment
		(start 331.9272 -276.879812)
		(end 331.82687 -276.980142)
		(width 0.088646)
		(layer "In6.Cu")
		(net "M_D_CPU0_SA_DQ<7>")
	)
	(segment
		(start 331.52588 -276.980142)
		(end 331.28331 -277.222712)
		(width 0.088646)
		(layer "In6.Cu")
		(net "M_D_CPU0_SA_DQ<7>")
	)
	(segment
		(start 277.162768 -307.391308)
		(end 275.813774 -307.391308)
		(width 0.18288)
		(layer "In6.Cu")
		(net "M_D_CPU0_SA_DQ<7>")
	)
	(segment
		(start 342.116664 -272.96364)
		(end 342.101932 -272.955004)
		(width 0.088646)
		(layer "In6.Cu")
		(net "M_D_CPU0_SA_DQ<7>")
	)
	(segment
		(start 288.92119 -307.45811)
		(end 288.137346 -308.241954)
		(width 0.18288)
		(layer "In6.Cu")
		(net "M_D_CPU0_SA_DQ<7>")
	)
	(segment
		(start 341.176864 -272.96364)
		(end 341.162132 -272.955004)
		(width 0.088646)
		(layer "In6.Cu")
		(net "M_D_CPU0_SA_DQ<7>")
	)
	(segment
		(start 272.85823 -307.161692)
		(end 272.69821 -307.321712)
		(width 0.18288)
		(layer "In6.Cu")
		(net "M_D_CPU0_SA_DQ<7>")
	)
	(segment
		(start 270.08455 -306.691792)
		(end 270.08455 -307.231288)
		(width 0.18288)
		(layer "In6.Cu")
		(net "M_D_CPU0_SA_DQ<7>")
	)
	(segment
		(start 274.940014 -306.10302)
		(end 274.940014 -307.208428)
		(width 0.18288)
		(layer "In6.Cu")
		(net "M_D_CPU0_SA_DQ<7>")
	)
	(segment
		(start 270.08455 -307.231288)
		(end 269.92453 -307.391308)
		(width 0.18288)
		(layer "In6.Cu")
		(net "M_D_CPU0_SA_DQ<7>")
	)
	(segment
		(start 275.813774 -307.391308)
		(end 275.630894 -307.208428)
		(width 0.18288)
		(layer "In6.Cu")
		(net "M_D_CPU0_SA_DQ<7>")
	)
	(segment
		(start 301.70374 -299.746924)
		(end 301.800768 -299.843952)
		(width 0.18288)
		(layer "In6.Cu")
		(net "M_D_CPU0_SA_DQ<7>")
	)
	(segment
		(start 332.144878 -276.214078)
		(end 331.9272 -276.431756)
		(width 0.088646)
		(layer "In6.Cu")
		(net "M_D_CPU0_SA_DQ<7>")
	)
	(segment
		(start 335.160112 -274.257008)
		(end 335.160112 -274.266914)
		(width 0.088646)
		(layer "In6.Cu")
		(net "M_D_CPU0_SA_DQ<7>")
	)
	(segment
		(start 343.996264 -272.96364)
		(end 343.981532 -272.955004)
		(width 0.088646)
		(layer "In6.Cu")
		(net "M_D_CPU0_SA_DQ<7>")
	)
	(segment
		(start 275.630894 -306.059586)
		(end 275.448014 -305.876706)
		(width 0.18288)
		(layer "In6.Cu")
		(net "M_D_CPU0_SA_DQ<7>")
	)
	(segment
		(start 270.24457 -306.531772)
		(end 270.08455 -306.691792)
		(width 0.18288)
		(layer "In6.Cu")
		(net "M_D_CPU0_SA_DQ<7>")
	)
	(segment
		(start 314.119006 -292.550596)
		(end 313.572906 -292.550596)
		(width 0.18288)
		(layer "In6.Cu")
		(net "M_D_CPU0_SA_DQ<7>")
	)
	(segment
		(start 331.28331 -277.222712)
		(end 331.177646 -277.222712)
		(width 0.18288)
		(layer "In6.Cu")
		(net "M_D_CPU0_SA_DQ<7>")
	)
	(segment
		(start 301.70374 -299.488352)
		(end 301.70374 -299.746924)
		(width 0.18288)
		(layer "In6.Cu")
		(net "M_D_CPU0_SA_DQ<7>")
	)
	(segment
		(start 302.289464 -299.355256)
		(end 302.192436 -299.258228)
		(width 0.18288)
		(layer "In6.Cu")
		(net "M_D_CPU0_SA_DQ<7>")
	)
	(segment
		(start 272.69821 -307.321712)
		(end 272.32483 -307.321712)
		(width 0.18288)
		(layer "In6.Cu")
		(net "M_D_CPU0_SA_DQ<7>")
	)
	(segment
		(start 278.036528 -306.814982)
		(end 277.853648 -306.632102)
		(width 0.18288)
		(layer "In6.Cu")
		(net "M_D_CPU0_SA_DQ<7>")
	)
	(segment
		(start 273.01825 -306.531772)
		(end 272.85823 -306.691792)
		(width 0.18288)
		(layer "In6.Cu")
		(net "M_D_CPU0_SA_DQ<7>")
	)
	(segment
		(start 275.448014 -305.876706)
		(end 275.166328 -305.876706)
		(width 0.18288)
		(layer "In6.Cu")
		(net "M_D_CPU0_SA_DQ<7>")
	)
	(segment
		(start 295.566592 -303.576482)
		(end 295.151302 -303.991772)
		(width 0.18288)
		(layer "In6.Cu")
		(net "M_D_CPU0_SA_DQ<7>")
	)
	(segment
		(start 272.16481 -306.691792)
		(end 272.00479 -306.531772)
		(width 0.18288)
		(layer "In6.Cu")
		(net "M_D_CPU0_SA_DQ<7>")
	)
	(segment
		(start 304.441606 -298.267882)
		(end 303.63541 -298.267882)
		(width 0.18288)
		(layer "In6.Cu")
		(net "M_D_CPU0_SA_DQ<7>")
	)
	(segment
		(start 273.71167 -307.391308)
		(end 273.55165 -307.231288)
		(width 0.18288)
		(layer "In6.Cu")
		(net "M_D_CPU0_SA_DQ<7>")
	)
	(segment
		(start 334.047592 -274.582636)
		(end 334.03286 -274.591272)
		(width 0.088646)
		(layer "In6.Cu")
		(net "M_D_CPU0_SA_DQ<7>")
	)
	(segment
		(start 273.39163 -306.531772)
		(end 273.01825 -306.531772)
		(width 0.18288)
		(layer "In6.Cu")
		(net "M_D_CPU0_SA_DQ<7>")
	)
	(segment
		(start 301.933864 -299.258228)
		(end 301.70374 -299.488352)
		(width 0.18288)
		(layer "In6.Cu")
		(net "M_D_CPU0_SA_DQ<7>")
	)
	(segment
		(start 301.800768 -300.102524)
		(end 301.311564 -300.591728)
		(width 0.18288)
		(layer "In6.Cu")
		(net "M_D_CPU0_SA_DQ<7>")
	)
	(segment
		(start 270.77797 -306.691792)
		(end 270.61795 -306.531772)
		(width 0.18288)
		(layer "In6.Cu")
		(net "M_D_CPU0_SA_DQ<7>")
	)
	(segment
		(start 332.340458 -275.876258)
		(end 332.340458 -275.8948)
		(width 0.088646)
		(layer "In6.Cu")
		(net "M_D_CPU0_SA_DQ<7>")
	)
	(segment
		(start 312.531252 -293.59225)
		(end 311.735216 -293.59225)
		(width 0.18288)
		(layer "In6.Cu")
		(net "M_D_CPU0_SA_DQ<7>")
	)
	(segment
		(start 339.297264 -272.96364)
		(end 339.28685 -272.957544)
		(width 0.088646)
		(layer "In6.Cu")
		(net "M_D_CPU0_SA_DQ<7>")
	)
	(segment
		(start 306.640738 -296.494454)
		(end 306.215034 -296.494454)
		(width 0.18288)
		(layer "In6.Cu")
		(net "M_D_CPU0_SA_DQ<7>")
	)
	(segment
		(start 297.8912 -300.591728)
		(end 295.566592 -302.916336)
		(width 0.18288)
		(layer "In6.Cu")
		(net "M_D_CPU0_SA_DQ<7>")
	)
	(segment
		(start 331.177646 -277.222712)
		(end 328.222864 -278.446738)
		(width 0.18288)
		(layer "In6.Cu")
		(net "M_D_CPU0_SA_DQ<7>")
	)
	(segment
		(start 309.2831 -294.60952)
		(end 308.359302 -295.533318)
		(width 0.18288)
		(layer "In6.Cu")
		(net "M_D_CPU0_SA_DQ<7>")
	)
	(segment
		(start 271.47139 -306.691792)
		(end 271.47139 -307.231288)
		(width 0.18288)
		(layer "In6.Cu")
		(net "M_D_CPU0_SA_DQ<7>")
	)
	(segment
		(start 271.63141 -306.531772)
		(end 271.47139 -306.691792)
		(width 0.18288)
		(layer "In6.Cu")
		(net "M_D_CPU0_SA_DQ<7>")
	)
	(segment
		(start 271.31137 -307.391308)
		(end 270.93799 -307.391308)
		(width 0.18288)
		(layer "In6.Cu")
		(net "M_D_CPU0_SA_DQ<7>")
	)
	(segment
		(start 291.555678 -305.838606)
		(end 291.034978 -305.838606)
		(width 0.18288)
		(layer "In6.Cu")
		(net "M_D_CPU0_SA_DQ<7>")
	)
	(segment
		(start 344.340942 -273.453098)
		(end 344.275156 -273.387312)
		(width 0.088646)
		(layer "In6.Cu")
		(net "M_D_CPU0_SA_DQ<7>")
	)
	(segment
		(start 271.47139 -307.231288)
		(end 271.31137 -307.391308)
		(width 0.18288)
		(layer "In6.Cu")
		(net "M_D_CPU0_SA_DQ<7>")
	)
	(segment
		(start 275.630894 -307.208428)
		(end 275.630894 -306.059586)
		(width 0.18288)
		(layer "In6.Cu")
		(net "M_D_CPU0_SA_DQ<7>")
	)
	(segment
		(start 272.32483 -307.321712)
		(end 272.16481 -307.161692)
		(width 0.18288)
		(layer "In6.Cu")
		(net "M_D_CPU0_SA_DQ<7>")
	)
	(segment
		(start 292.441376 -304.952908)
		(end 291.555678 -305.838606)
		(width 0.18288)
		(layer "In6.Cu")
		(net "M_D_CPU0_SA_DQ<7>")
	)
	(segment
		(start 275.166328 -305.876706)
		(end 274.940014 -306.10302)
		(width 0.18288)
		(layer "In6.Cu")
		(net "M_D_CPU0_SA_DQ<7>")
	)
	(segment
		(start 277.528528 -306.632102)
		(end 277.345648 -306.814982)
		(width 0.18288)
		(layer "In6.Cu")
		(net "M_D_CPU0_SA_DQ<7>")
	)
	(segment
		(start 303.63541 -298.267882)
		(end 302.548036 -299.355256)
		(width 0.18288)
		(layer "In6.Cu")
		(net "M_D_CPU0_SA_DQ<7>")
	)
	(segment
		(start 301.311564 -300.591728)
		(end 297.8912 -300.591728)
		(width 0.18288)
		(layer "In6.Cu")
		(net "M_D_CPU0_SA_DQ<7>")
	)
	(segment
		(start 295.151302 -303.991772)
		(end 294.364156 -303.991772)
		(width 0.18288)
		(layer "In6.Cu")
		(net "M_D_CPU0_SA_DQ<7>")
	)
	(segment
		(start 288.137346 -308.241954)
		(end 281.422348 -308.241954)
		(width 0.18288)
		(layer "In6.Cu")
		(net "M_D_CPU0_SA_DQ<7>")
	)
	(segment
		(start 313.572906 -292.550596)
		(end 312.531252 -293.59225)
		(width 0.18288)
		(layer "In6.Cu")
		(net "M_D_CPU0_SA_DQ<7>")
	)
	(segment
		(start 272.85823 -306.691792)
		(end 272.85823 -307.161692)
		(width 0.18288)
		(layer "In6.Cu")
		(net "M_D_CPU0_SA_DQ<7>")
	)
	(segment
		(start 277.853648 -306.632102)
		(end 277.528528 -306.632102)
		(width 0.18288)
		(layer "In6.Cu")
		(net "M_D_CPU0_SA_DQ<7>")
	)
	(segment
		(start 278.224996 -307.39334)
		(end 278.036528 -307.204872)
		(width 0.18288)
		(layer "In6.Cu")
		(net "M_D_CPU0_SA_DQ<7>")
	)
	(segment
		(start 278.036528 -307.204872)
		(end 278.036528 -306.814982)
		(width 0.18288)
		(layer "In6.Cu")
		(net "M_D_CPU0_SA_DQ<7>")
	)
	(segment
		(start 310.717946 -294.60952)
		(end 309.2831 -294.60952)
		(width 0.18288)
		(layer "In6.Cu")
		(net "M_D_CPU0_SA_DQ<7>")
	)
	(segment
		(start 344.00236 -272.967196)
		(end 343.996264 -272.96364)
		(width 0.088646)
		(layer "In6.Cu")
		(net "M_D_CPU0_SA_DQ<7>")
	)
	(segment
		(start 337.802474 -272.957544)
		(end 337.79206 -272.96364)
		(width 0.088646)
		(layer "In6.Cu")
		(net "M_D_CPU0_SA_DQ<7>")
	)
	(segment
		(start 308.359302 -295.533318)
		(end 307.601874 -295.533318)
		(width 0.18288)
		(layer "In6.Cu")
		(net "M_D_CPU0_SA_DQ<7>")
	)
	(segment
		(start 340.237064 -272.96364)
		(end 340.222332 -272.955004)
		(width 0.088646)
		(layer "In6.Cu")
		(net "M_D_CPU0_SA_DQ<7>")
	)
	(segment
		(start 334.98155 -274.586192)
		(end 334.97266 -274.591272)
		(width 0.088646)
		(layer "In6.Cu")
		(net "M_D_CPU0_SA_DQ<7>")
	)
	(segment
		(start 333.571596 -275.400008)
		(end 333.562706 -275.405088)
		(width 0.088646)
		(layer "In6.Cu")
		(net "M_D_CPU0_SA_DQ<7>")
	)
	(segment
		(start 311.735216 -293.59225)
		(end 310.717946 -294.60952)
		(width 0.18288)
		(layer "In6.Cu")
		(net "M_D_CPU0_SA_DQ<7>")
	)
	(segment
		(start 273.55165 -306.691792)
		(end 273.39163 -306.531772)
		(width 0.18288)
		(layer "In6.Cu")
		(net "M_D_CPU0_SA_DQ<7>")
	)
	(segment
		(start 295.566592 -302.916336)
		(end 295.566592 -303.576482)
		(width 0.18288)
		(layer "In6.Cu")
		(net "M_D_CPU0_SA_DQ<7>")
	)
	(segment
		(start 306.215034 -296.494454)
		(end 304.441606 -298.267882)
		(width 0.18288)
		(layer "In6.Cu")
		(net "M_D_CPU0_SA_DQ<7>")
	)
	(segment
		(start 273.55165 -307.231288)
		(end 273.55165 -306.691792)
		(width 0.18288)
		(layer "In6.Cu")
		(net "M_D_CPU0_SA_DQ<7>")
	)
	(segment
		(start 334.03286 -274.591272)
		(end 334.026764 -274.594828)
		(width 0.088646)
		(layer "In6.Cu")
		(net "M_D_CPU0_SA_DQ<7>")
	)
	(segment
		(start 270.77797 -307.231288)
		(end 270.77797 -306.691792)
		(width 0.18288)
		(layer "In6.Cu")
		(net "M_D_CPU0_SA_DQ<7>")
	)
	(segment
		(start 302.192436 -299.258228)
		(end 301.933864 -299.258228)
		(width 0.18288)
		(layer "In6.Cu")
		(net "M_D_CPU0_SA_DQ<7>")
	)
	(segment
		(start 272.16481 -307.161692)
		(end 272.16481 -306.691792)
		(width 0.18288)
		(layer "In6.Cu")
		(net "M_D_CPU0_SA_DQ<7>")
	)
	(segment
		(start 336.852514 -272.96364)
		(end 336.846418 -272.967196)
		(width 0.088646)
		(layer "In6.Cu")
		(net "M_D_CPU0_SA_DQ<7>")
	)
	(segment
		(start 270.61795 -306.531772)
		(end 270.24457 -306.531772)
		(width 0.18288)
		(layer "In6.Cu")
		(net "M_D_CPU0_SA_DQ<7>")
	)
	(segment
		(start 336.862928 -272.957544)
		(end 336.852514 -272.96364)
		(width 0.088646)
		(layer "In6.Cu")
		(net "M_D_CPU0_SA_DQ<7>")
	)
	(segment
		(start 281.422348 -308.241954)
		(end 280.573734 -307.39334)
		(width 0.18288)
		(layer "In6.Cu")
		(net "M_D_CPU0_SA_DQ<7>")
	)
	(segment
		(start 331.82687 -276.980142)
		(end 331.52588 -276.980142)
		(width 0.088646)
		(layer "In6.Cu")
		(net "M_D_CPU0_SA_DQ<7>")
	)
	(segment
		(start 332.161896 -276.214078)
		(end 332.144878 -276.214078)
		(width 0.088646)
		(layer "In6.Cu")
		(net "M_D_CPU0_SA_DQ<7>")
	)
	(segment
		(start 331.9272 -276.431756)
		(end 331.9272 -276.879812)
		(width 0.088646)
		(layer "In6.Cu")
		(net "M_D_CPU0_SA_DQ<7>")
	)
	(segment
		(start 277.345648 -307.208428)
		(end 277.162768 -307.391308)
		(width 0.18288)
		(layer "In6.Cu")
		(net "M_D_CPU0_SA_DQ<7>")
	)
	(segment
		(start 272.00479 -306.531772)
		(end 271.63141 -306.531772)
		(width 0.18288)
		(layer "In6.Cu")
		(net "M_D_CPU0_SA_DQ<7>")
	)
	(arc
		(start 336.38236 -273.777456)
		(mid 336.195162 -273.827599)
		(end 336.007964 -273.777456)
		(width 0.088646)
		(layer "In6.Cu")
		(net "M_D_CPU0_SA_DQ<7>")
	)
	(arc
		(start 343.981532 -272.955004)
		(mid 343.705057 -272.887684)
		(end 343.43086 -272.96364)
		(width 0.088646)
		(layer "In6.Cu")
		(net "M_D_CPU0_SA_DQ<7>")
	)
	(arc
		(start 333.750158 -275.08073)
		(mid 333.702479 -275.26363)
		(end 333.571596 -275.400008)
		(width 0.088646)
		(layer "In6.Cu")
		(net "M_D_CPU0_SA_DQ<7>")
	)
	(arc
		(start 335.44256 -273.777456)
		(mid 335.238225 -273.980061)
		(end 335.160112 -274.257008)
		(width 0.088646)
		(layer "In6.Cu")
		(net "M_D_CPU0_SA_DQ<7>")
	)
	(arc
		(start 343.056464 -272.96364)
		(mid 342.773762 -272.887864)
		(end 342.49106 -272.96364)
		(width 0.088646)
		(layer "In6.Cu")
		(net "M_D_CPU0_SA_DQ<7>")
	)
	(arc
		(start 341.55126 -272.96364)
		(mid 341.364062 -273.013783)
		(end 341.176864 -272.96364)
		(width 0.088646)
		(layer "In6.Cu")
		(net "M_D_CPU0_SA_DQ<7>")
	)
	(arc
		(start 336.846418 -272.967196)
		(mid 336.643831 -273.173547)
		(end 336.569812 -273.453098)
		(width 0.088646)
		(layer "In6.Cu")
		(net "M_D_CPU0_SA_DQ<7>")
	)
	(arc
		(start 334.026764 -274.594828)
		(mid 333.824177 -274.801179)
		(end 333.750158 -275.08073)
		(width 0.088646)
		(layer "In6.Cu")
		(net "M_D_CPU0_SA_DQ<7>")
	)
	(arc
		(start 338.357718 -272.96364)
		(mid 338.080905 -272.88777)
		(end 337.802474 -272.957544)
		(width 0.088646)
		(layer "In6.Cu")
		(net "M_D_CPU0_SA_DQ<7>")
	)
	(arc
		(start 334.97266 -274.591272)
		(mid 334.785462 -274.641415)
		(end 334.598264 -274.591272)
		(width 0.088646)
		(layer "In6.Cu")
		(net "M_D_CPU0_SA_DQ<7>")
	)
	(arc
		(start 341.162132 -272.955004)
		(mid 340.885657 -272.887684)
		(end 340.61146 -272.96364)
		(width 0.088646)
		(layer "In6.Cu")
		(net "M_D_CPU0_SA_DQ<7>")
	)
	(arc
		(start 342.101932 -272.955004)
		(mid 341.825457 -272.887684)
		(end 341.55126 -272.96364)
		(width 0.088646)
		(layer "In6.Cu")
		(net "M_D_CPU0_SA_DQ<7>")
	)
	(arc
		(start 339.67166 -272.96364)
		(mid 339.484462 -273.013783)
		(end 339.297264 -272.96364)
		(width 0.088646)
		(layer "In6.Cu")
		(net "M_D_CPU0_SA_DQ<7>")
	)
	(arc
		(start 337.79206 -272.96364)
		(mid 337.604862 -273.013783)
		(end 337.417664 -272.96364)
		(width 0.088646)
		(layer "In6.Cu")
		(net "M_D_CPU0_SA_DQ<7>")
	)
	(arc
		(start 332.622906 -275.405088)
		(mid 332.42062 -275.604069)
		(end 332.340458 -275.876258)
		(width 0.088646)
		(layer "In6.Cu")
		(net "M_D_CPU0_SA_DQ<7>")
	)
	(arc
		(start 337.417664 -272.96364)
		(mid 337.141105 -272.887897)
		(end 336.862928 -272.957544)
		(width 0.088646)
		(layer "In6.Cu")
		(net "M_D_CPU0_SA_DQ<7>")
	)
	(arc
		(start 334.598264 -274.591272)
		(mid 334.324065 -274.515437)
		(end 334.047592 -274.582636)
		(width 0.088646)
		(layer "In6.Cu")
		(net "M_D_CPU0_SA_DQ<7>")
	)
	(arc
		(start 336.569812 -273.453098)
		(mid 336.522133 -273.635998)
		(end 336.39125 -273.772376)
		(width 0.088646)
		(layer "In6.Cu")
		(net "M_D_CPU0_SA_DQ<7>")
	)
	(arc
		(start 344.275156 -273.387312)
		(mid 344.187868 -273.145356)
		(end 344.00236 -272.967196)
		(width 0.088646)
		(layer "In6.Cu")
		(net "M_D_CPU0_SA_DQ<7>")
	)
	(arc
		(start 340.222332 -272.955004)
		(mid 339.945857 -272.887684)
		(end 339.67166 -272.96364)
		(width 0.088646)
		(layer "In6.Cu")
		(net "M_D_CPU0_SA_DQ<7>")
	)
	(arc
		(start 343.43086 -272.96364)
		(mid 343.243662 -273.013783)
		(end 343.056464 -272.96364)
		(width 0.088646)
		(layer "In6.Cu")
		(net "M_D_CPU0_SA_DQ<7>")
	)
	(arc
		(start 339.28685 -272.957544)
		(mid 339.008672 -272.887821)
		(end 338.732114 -272.96364)
		(width 0.088646)
		(layer "In6.Cu")
		(net "M_D_CPU0_SA_DQ<7>")
	)
	(arc
		(start 336.007964 -273.777456)
		(mid 335.725262 -273.70168)
		(end 335.44256 -273.777456)
		(width 0.088646)
		(layer "In6.Cu")
		(net "M_D_CPU0_SA_DQ<7>")
	)
	(arc
		(start 340.61146 -272.96364)
		(mid 340.424262 -273.013783)
		(end 340.237064 -272.96364)
		(width 0.088646)
		(layer "In6.Cu")
		(net "M_D_CPU0_SA_DQ<7>")
	)
	(arc
		(start 333.562706 -275.405088)
		(mid 333.375508 -275.455231)
		(end 333.18831 -275.405088)
		(width 0.088646)
		(layer "In6.Cu")
		(net "M_D_CPU0_SA_DQ<7>")
	)
	(arc
		(start 333.18831 -275.405088)
		(mid 332.905608 -275.329346)
		(end 332.622906 -275.405088)
		(width 0.088646)
		(layer "In6.Cu")
		(net "M_D_CPU0_SA_DQ<7>")
	)
	(arc
		(start 338.732114 -272.96364)
		(mid 338.544916 -273.013783)
		(end 338.357718 -272.96364)
		(width 0.088646)
		(layer "In6.Cu")
		(net "M_D_CPU0_SA_DQ<7>")
	)
	(arc
		(start 342.49106 -272.96364)
		(mid 342.303862 -273.013783)
		(end 342.116664 -272.96364)
		(width 0.088646)
		(layer "In6.Cu")
		(net "M_D_CPU0_SA_DQ<7>")
	)
	(arc
		(start 332.340458 -275.8948)
		(mid 332.292779 -276.0777)
		(end 332.161896 -276.214078)
		(width 0.088646)
		(layer "In6.Cu")
		(net "M_D_CPU0_SA_DQ<7>")
	)
	(arc
		(start 335.160112 -274.266914)
		(mid 335.112433 -274.449814)
		(end 334.98155 -274.586192)
		(width 0.088646)
		(layer "In6.Cu")
		(net "M_D_CPU0_SA_DQ<7>")
	)
	(segment
		(start 265.601958 -309.56123)
		(end 265.601958 -309.235602)
		(width 0.20066)
		(layer "F.Cu")
		(net "M_D_CPU0_SA_DQ<6>")
	)
	(segment
		(start 262.765286 -309.091838)
		(end 262.51027 -309.091838)
		(width 0.101854)
		(layer "F.Cu")
		(net "M_D_CPU0_SA_DQ<6>")
	)
	(segment
		(start 264.825226 -309.091838)
		(end 262.765286 -309.091838)
		(width 0.1016)
		(layer "F.Cu")
		(net "M_D_CPU0_SA_DQ<6>")
	)
	(segment
		(start 265.458194 -309.091838)
		(end 264.825226 -309.091838)
		(width 0.20066)
		(layer "F.Cu")
		(net "M_D_CPU0_SA_DQ<6>")
	)
	(segment
		(start 261.762748 -309.081678)
		(end 261.327646 -309.51678)
		(width 0.20066)
		(layer "F.Cu")
		(net "M_D_CPU0_SA_DQ<6>")
	)
	(segment
		(start 345.123516 -273.730974)
		(end 345.123516 -274.26666)
		(width 0.20066)
		(layer "F.Cu")
		(net "M_D_CPU0_SA_DQ<6>")
	)
	(segment
		(start 267.724382 -309.51678)
		(end 266.409678 -309.51678)
		(width 0.20066)
		(layer "F.Cu")
		(net "M_D_CPU0_SA_DQ<6>")
	)
	(segment
		(start 262.51027 -309.091838)
		(end 262.50011 -309.081678)
		(width 0.101854)
		(layer "F.Cu")
		(net "M_D_CPU0_SA_DQ<6>")
	)
	(segment
		(start 268.829282 -309.51678)
		(end 267.724382 -309.51678)
		(width 0.20066)
		(layer "F.Cu")
		(net "M_D_CPU0_SA_DQ<6>")
	)
	(segment
		(start 265.601958 -309.235602)
		(end 265.458194 -309.091838)
		(width 0.20066)
		(layer "F.Cu")
		(net "M_D_CPU0_SA_DQ<6>")
	)
	(segment
		(start 261.327646 -309.51678)
		(end 260.180582 -309.51678)
		(width 0.20066)
		(layer "F.Cu")
		(net "M_D_CPU0_SA_DQ<6>")
	)
	(segment
		(start 266.197842 -309.728616)
		(end 265.769344 -309.728616)
		(width 0.20066)
		(layer "F.Cu")
		(net "M_D_CPU0_SA_DQ<6>")
	)
	(segment
		(start 262.50011 -309.081678)
		(end 261.762748 -309.081678)
		(width 0.20066)
		(layer "F.Cu")
		(net "M_D_CPU0_SA_DQ<6>")
	)
	(segment
		(start 265.769344 -309.728616)
		(end 265.601958 -309.56123)
		(width 0.20066)
		(layer "F.Cu")
		(net "M_D_CPU0_SA_DQ<6>")
	)
	(segment
		(start 345.123516 -274.26666)
		(end 345.123262 -274.266914)
		(width 0.20066)
		(layer "F.Cu")
		(net "M_D_CPU0_SA_DQ<6>")
	)
	(segment
		(start 266.409678 -309.51678)
		(end 266.197842 -309.728616)
		(width 0.20066)
		(layer "F.Cu")
		(net "M_D_CPU0_SA_DQ<6>")
	)
	(segment
		(start 306.61229 -298.230798)
		(end 306.215034 -298.230798)
		(width 0.18288)
		(layer "In6.Cu")
		(net "M_D_CPU0_SA_DQ<6>")
	)
	(segment
		(start 270.973296 -310.23687)
		(end 270.790416 -310.05399)
		(width 0.18288)
		(layer "In6.Cu")
		(net "M_D_CPU0_SA_DQ<6>")
	)
	(segment
		(start 308.112668 -297.288204)
		(end 307.554884 -297.288204)
		(width 0.18288)
		(layer "In6.Cu")
		(net "M_D_CPU0_SA_DQ<6>")
	)
	(segment
		(start 340.156546 -273.76882)
		(end 340.141814 -273.777456)
		(width 0.088646)
		(layer "In6.Cu")
		(net "M_D_CPU0_SA_DQ<6>")
	)
	(segment
		(start 304.32883 -300.117002)
		(end 303.915318 -300.117002)
		(width 0.18288)
		(layer "In6.Cu")
		(net "M_D_CPU0_SA_DQ<6>")
	)
	(segment
		(start 334.220058 -275.876258)
		(end 334.220058 -275.8948)
		(width 0.088646)
		(layer "In6.Cu")
		(net "M_D_CPU0_SA_DQ<6>")
	)
	(segment
		(start 298.295314 -302.02505)
		(end 297.939206 -302.02505)
		(width 0.18288)
		(layer "In6.Cu")
		(net "M_D_CPU0_SA_DQ<6>")
	)
	(segment
		(start 275.002752 -308.791356)
		(end 274.842732 -308.951376)
		(width 0.18288)
		(layer "In6.Cu")
		(net "M_D_CPU0_SA_DQ<6>")
	)
	(segment
		(start 332.686914 -276.78253)
		(end 332.686914 -277.618444)
		(width 0.088646)
		(layer "In6.Cu")
		(net "M_D_CPU0_SA_DQ<6>")
	)
	(segment
		(start 271.664176 -308.812438)
		(end 271.481296 -308.995318)
		(width 0.18288)
		(layer "In6.Cu")
		(net "M_D_CPU0_SA_DQ<6>")
	)
	(segment
		(start 278.31796 -309.388256)
		(end 277.995126 -309.065422)
		(width 0.18288)
		(layer "In6.Cu")
		(net "M_D_CPU0_SA_DQ<6>")
	)
	(segment
		(start 286.020256 -309.762144)
		(end 285.840424 -309.941976)
		(width 0.18288)
		(layer "In6.Cu")
		(net "M_D_CPU0_SA_DQ<6>")
	)
	(segment
		(start 294.162734 -305.691794)
		(end 293.196518 -306.65801)
		(width 0.18288)
		(layer "In6.Cu")
		(net "M_D_CPU0_SA_DQ<6>")
	)
	(segment
		(start 295.53916 -305.497992)
		(end 295.345358 -305.691794)
		(width 0.18288)
		(layer "In6.Cu")
		(net "M_D_CPU0_SA_DQ<6>")
	)
	(segment
		(start 303.114456 -301.331376)
		(end 302.234092 -301.331376)
		(width 0.18288)
		(layer "In6.Cu")
		(net "M_D_CPU0_SA_DQ<6>")
	)
	(segment
		(start 271.481296 -308.995318)
		(end 271.481296 -310.05399)
		(width 0.18288)
		(layer "In6.Cu")
		(net "M_D_CPU0_SA_DQ<6>")
	)
	(segment
		(start 282.294584 -309.941976)
		(end 281.26182 -309.941976)
		(width 0.18288)
		(layer "In6.Cu")
		(net "M_D_CPU0_SA_DQ<6>")
	)
	(segment
		(start 312.068464 -296.444924)
		(end 311.23382 -296.444924)
		(width 0.18288)
		(layer "In6.Cu")
		(net "M_D_CPU0_SA_DQ<6>")
	)
	(segment
		(start 270.790416 -310.05399)
		(end 270.790416 -308.995318)
		(width 0.18288)
		(layer "In6.Cu")
		(net "M_D_CPU0_SA_DQ<6>")
	)
	(segment
		(start 303.915318 -300.117002)
		(end 303.633378 -300.398942)
		(width 0.18288)
		(layer "In6.Cu")
		(net "M_D_CPU0_SA_DQ<6>")
	)
	(segment
		(start 311.035192 -296.246296)
		(end 309.154576 -296.246296)
		(width 0.18288)
		(layer "In6.Cu")
		(net "M_D_CPU0_SA_DQ<6>")
	)
	(segment
		(start 286.713676 -309.941976)
		(end 286.533844 -309.762144)
		(width 0.18288)
		(layer "In6.Cu")
		(net "M_D_CPU0_SA_DQ<6>")
	)
	(segment
		(start 280.411174 -309.09133)
		(end 279.294336 -309.09133)
		(width 0.18288)
		(layer "In6.Cu")
		(net "M_D_CPU0_SA_DQ<6>")
	)
	(segment
		(start 342.031828 -273.77136)
		(end 342.021414 -273.777456)
		(width 0.088646)
		(layer "In6.Cu")
		(net "M_D_CPU0_SA_DQ<6>")
	)
	(segment
		(start 298.455334 -302.981614)
		(end 298.455334 -302.18507)
		(width 0.18288)
		(layer "In6.Cu")
		(net "M_D_CPU0_SA_DQ<6>")
	)
	(segment
		(start 282.988004 -309.653686)
		(end 282.582874 -309.653686)
		(width 0.18288)
		(layer "In6.Cu")
		(net "M_D_CPU0_SA_DQ<6>")
	)
	(segment
		(start 314.749942 -294.284908)
		(end 314.290456 -294.744394)
		(width 0.18288)
		(layer "In6.Cu")
		(net "M_D_CPU0_SA_DQ<6>")
	)
	(segment
		(start 276.996906 -309.065422)
		(end 276.643846 -309.418482)
		(width 0.18288)
		(layer "In6.Cu")
		(net "M_D_CPU0_SA_DQ<6>")
	)
	(segment
		(start 298.455334 -302.18507)
		(end 298.295314 -302.02505)
		(width 0.18288)
		(layer "In6.Cu")
		(net "M_D_CPU0_SA_DQ<6>")
	)
	(segment
		(start 282.582874 -309.653686)
		(end 282.294584 -309.941976)
		(width 0.18288)
		(layer "In6.Cu")
		(net "M_D_CPU0_SA_DQ<6>")
	)
	(segment
		(start 289.465766 -309.231538)
		(end 288.702242 -309.231538)
		(width 0.18288)
		(layer "In6.Cu")
		(net "M_D_CPU0_SA_DQ<6>")
	)
	(segment
		(start 331.28331 -278.421592)
		(end 330.994766 -278.421592)
		(width 0.18288)
		(layer "In6.Cu")
		(net "M_D_CPU0_SA_DQ<6>")
	)
	(segment
		(start 297.288712 -303.74844)
		(end 296.84726 -304.189892)
		(width 0.18288)
		(layer "In6.Cu")
		(net "M_D_CPU0_SA_DQ<6>")
	)
	(segment
		(start 275.536152 -308.951376)
		(end 275.376132 -308.791356)
		(width 0.18288)
		(layer "In6.Cu")
		(net "M_D_CPU0_SA_DQ<6>")
	)
	(segment
		(start 335.91246 -274.591272)
		(end 335.900268 -274.598384)
		(width 0.088646)
		(layer "In6.Cu")
		(net "M_D_CPU0_SA_DQ<6>")
	)
	(segment
		(start 270.790416 -308.995318)
		(end 270.607536 -308.812438)
		(width 0.18288)
		(layer "In6.Cu")
		(net "M_D_CPU0_SA_DQ<6>")
	)
	(segment
		(start 275.696172 -309.418482)
		(end 275.536152 -309.258462)
		(width 0.18288)
		(layer "In6.Cu")
		(net "M_D_CPU0_SA_DQ<6>")
	)
	(segment
		(start 297.601894 -303.141634)
		(end 297.459146 -303.141634)
		(width 0.18288)
		(layer "In6.Cu")
		(net "M_D_CPU0_SA_DQ<6>")
	)
	(segment
		(start 287.991804 -309.941976)
		(end 286.713676 -309.941976)
		(width 0.18288)
		(layer "In6.Cu")
		(net "M_D_CPU0_SA_DQ<6>")
	)
	(segment
		(start 272.988024 -308.812438)
		(end 271.664176 -308.812438)
		(width 0.18288)
		(layer "In6.Cu")
		(net "M_D_CPU0_SA_DQ<6>")
	)
	(segment
		(start 311.23382 -296.444924)
		(end 311.035192 -296.246296)
		(width 0.18288)
		(layer "In6.Cu")
		(net "M_D_CPU0_SA_DQ<6>")
	)
	(segment
		(start 331.883766 -278.421592)
		(end 331.28331 -278.421592)
		(width 0.088646)
		(layer "In6.Cu")
		(net "M_D_CPU0_SA_DQ<6>")
	)
	(segment
		(start 297.459146 -303.141634)
		(end 297.288712 -303.312068)
		(width 0.18288)
		(layer "In6.Cu")
		(net "M_D_CPU0_SA_DQ<6>")
	)
	(segment
		(start 297.939206 -302.02505)
		(end 297.761914 -302.202342)
		(width 0.18288)
		(layer "In6.Cu")
		(net "M_D_CPU0_SA_DQ<6>")
	)
	(segment
		(start 313.318144 -295.183814)
		(end 313.318144 -295.195244)
		(width 0.18288)
		(layer "In6.Cu")
		(net "M_D_CPU0_SA_DQ<6>")
	)
	(segment
		(start 288.702242 -309.231538)
		(end 287.991804 -309.941976)
		(width 0.18288)
		(layer "In6.Cu")
		(net "M_D_CPU0_SA_DQ<6>")
	)
	(segment
		(start 296.502836 -304.189892)
		(end 295.53916 -305.153568)
		(width 0.18288)
		(layer "In6.Cu")
		(net "M_D_CPU0_SA_DQ<6>")
	)
	(segment
		(start 307.554884 -297.288204)
		(end 306.61229 -298.230798)
		(width 0.18288)
		(layer "In6.Cu")
		(net "M_D_CPU0_SA_DQ<6>")
	)
	(segment
		(start 297.761914 -302.202342)
		(end 297.761914 -302.981614)
		(width 0.18288)
		(layer "In6.Cu")
		(net "M_D_CPU0_SA_DQ<6>")
	)
	(segment
		(start 274.842732 -309.258462)
		(end 274.682712 -309.418482)
		(width 0.18288)
		(layer "In6.Cu")
		(net "M_D_CPU0_SA_DQ<6>")
	)
	(segment
		(start 269.533624 -308.812438)
		(end 268.829282 -309.51678)
		(width 0.18288)
		(layer "In6.Cu")
		(net "M_D_CPU0_SA_DQ<6>")
	)
	(segment
		(start 314.290456 -294.744394)
		(end 313.757564 -294.744394)
		(width 0.18288)
		(layer "In6.Cu")
		(net "M_D_CPU0_SA_DQ<6>")
	)
	(segment
		(start 291.492178 -307.552852)
		(end 291.144452 -307.552852)
		(width 0.18288)
		(layer "In6.Cu")
		(net "M_D_CPU0_SA_DQ<6>")
	)
	(segment
		(start 303.633378 -300.812454)
		(end 303.114456 -301.331376)
		(width 0.18288)
		(layer "In6.Cu")
		(net "M_D_CPU0_SA_DQ<6>")
	)
	(segment
		(start 295.53916 -305.153568)
		(end 295.53916 -305.497992)
		(width 0.18288)
		(layer "In6.Cu")
		(net "M_D_CPU0_SA_DQ<6>")
	)
	(segment
		(start 314.749942 -293.551864)
		(end 314.749942 -294.284908)
		(width 0.18288)
		(layer "In6.Cu")
		(net "M_D_CPU0_SA_DQ<6>")
	)
	(segment
		(start 300.423834 -303.141634)
		(end 298.615354 -303.141634)
		(width 0.18288)
		(layer "In6.Cu")
		(net "M_D_CPU0_SA_DQ<6>")
	)
	(segment
		(start 333.65821 -276.219158)
		(end 333.643478 -276.210522)
		(width 0.088646)
		(layer "In6.Cu")
		(net "M_D_CPU0_SA_DQ<6>")
	)
	(segment
		(start 341.096346 -273.76882)
		(end 341.081614 -273.777456)
		(width 0.088646)
		(layer "In6.Cu")
		(net "M_D_CPU0_SA_DQ<6>")
	)
	(segment
		(start 271.298416 -310.23687)
		(end 270.973296 -310.23687)
		(width 0.18288)
		(layer "In6.Cu")
		(net "M_D_CPU0_SA_DQ<6>")
	)
	(segment
		(start 273.594068 -309.418482)
		(end 272.988024 -308.812438)
		(width 0.18288)
		(layer "In6.Cu")
		(net "M_D_CPU0_SA_DQ<6>")
	)
	(segment
		(start 274.682712 -309.418482)
		(end 273.594068 -309.418482)
		(width 0.18288)
		(layer "In6.Cu")
		(net "M_D_CPU0_SA_DQ<6>")
	)
	(segment
		(start 337.039712 -274.257008)
		(end 337.039712 -274.266914)
		(width 0.088646)
		(layer "In6.Cu")
		(net "M_D_CPU0_SA_DQ<6>")
	)
	(segment
		(start 302.234092 -301.331376)
		(end 300.423834 -303.141634)
		(width 0.18288)
		(layer "In6.Cu")
		(net "M_D_CPU0_SA_DQ<6>")
	)
	(segment
		(start 274.842732 -308.951376)
		(end 274.842732 -309.258462)
		(width 0.18288)
		(layer "In6.Cu")
		(net "M_D_CPU0_SA_DQ<6>")
	)
	(segment
		(start 338.272374 -273.77136)
		(end 338.26196 -273.777456)
		(width 0.088646)
		(layer "In6.Cu")
		(net "M_D_CPU0_SA_DQ<6>")
	)
	(segment
		(start 271.481296 -310.05399)
		(end 271.298416 -310.23687)
		(width 0.18288)
		(layer "In6.Cu")
		(net "M_D_CPU0_SA_DQ<6>")
	)
	(segment
		(start 275.376132 -308.791356)
		(end 275.002752 -308.791356)
		(width 0.18288)
		(layer "In6.Cu")
		(net "M_D_CPU0_SA_DQ<6>")
	)
	(segment
		(start 293.196518 -306.65801)
		(end 292.38702 -306.65801)
		(width 0.18288)
		(layer "In6.Cu")
		(net "M_D_CPU0_SA_DQ<6>")
	)
	(segment
		(start 297.288712 -303.312068)
		(end 297.288712 -303.74844)
		(width 0.18288)
		(layer "In6.Cu")
		(net "M_D_CPU0_SA_DQ<6>")
	)
	(segment
		(start 281.26182 -309.941976)
		(end 280.411174 -309.09133)
		(width 0.18288)
		(layer "In6.Cu")
		(net "M_D_CPU0_SA_DQ<6>")
	)
	(segment
		(start 295.345358 -305.691794)
		(end 294.162734 -305.691794)
		(width 0.18288)
		(layer "In6.Cu")
		(net "M_D_CPU0_SA_DQ<6>")
	)
	(segment
		(start 336.86115 -274.586192)
		(end 336.85226 -274.591272)
		(width 0.088646)
		(layer "In6.Cu")
		(net "M_D_CPU0_SA_DQ<6>")
	)
	(segment
		(start 329.093576 -279.20823)
		(end 314.749942 -293.551864)
		(width 0.18288)
		(layer "In6.Cu")
		(net "M_D_CPU0_SA_DQ<6>")
	)
	(segment
		(start 291.144452 -307.552852)
		(end 289.465766 -309.231538)
		(width 0.18288)
		(layer "In6.Cu")
		(net "M_D_CPU0_SA_DQ<6>")
	)
	(segment
		(start 309.154576 -296.246296)
		(end 308.112668 -297.288204)
		(width 0.18288)
		(layer "In6.Cu")
		(net "M_D_CPU0_SA_DQ<6>")
	)
	(segment
		(start 292.38702 -306.65801)
		(end 291.492178 -307.552852)
		(width 0.18288)
		(layer "In6.Cu")
		(net "M_D_CPU0_SA_DQ<6>")
	)
	(segment
		(start 344.56497 -273.835368)
		(end 344.481912 -273.7866)
		(width 0.088646)
		(layer "In6.Cu")
		(net "M_D_CPU0_SA_DQ<6>")
	)
	(segment
		(start 306.215034 -298.230798)
		(end 304.32883 -300.117002)
		(width 0.18288)
		(layer "In6.Cu")
		(net "M_D_CPU0_SA_DQ<6>")
	)
	(segment
		(start 279.294336 -309.09133)
		(end 278.99741 -309.388256)
		(width 0.18288)
		(layer "In6.Cu")
		(net "M_D_CPU0_SA_DQ<6>")
	)
	(segment
		(start 334.041496 -276.214078)
		(end 334.032606 -276.219158)
		(width 0.088646)
		(layer "In6.Cu")
		(net "M_D_CPU0_SA_DQ<6>")
	)
	(segment
		(start 285.840424 -309.941976)
		(end 283.276294 -309.941976)
		(width 0.18288)
		(layer "In6.Cu")
		(net "M_D_CPU0_SA_DQ<6>")
	)
	(segment
		(start 278.99741 -309.388256)
		(end 278.31796 -309.388256)
		(width 0.18288)
		(layer "In6.Cu")
		(net "M_D_CPU0_SA_DQ<6>")
	)
	(segment
		(start 296.84726 -304.189892)
		(end 296.502836 -304.189892)
		(width 0.18288)
		(layer "In6.Cu")
		(net "M_D_CPU0_SA_DQ<6>")
	)
	(segment
		(start 335.451196 -275.400008)
		(end 335.442306 -275.405088)
		(width 0.088646)
		(layer "In6.Cu")
		(net "M_D_CPU0_SA_DQ<6>")
	)
	(segment
		(start 343.537286 -273.783806)
		(end 343.511632 -273.76882)
		(width 0.088646)
		(layer "In6.Cu")
		(net "M_D_CPU0_SA_DQ<6>")
	)
	(segment
		(start 277.995126 -309.065422)
		(end 276.996906 -309.065422)
		(width 0.18288)
		(layer "In6.Cu")
		(net "M_D_CPU0_SA_DQ<6>")
	)
	(segment
		(start 297.761914 -302.981614)
		(end 297.601894 -303.141634)
		(width 0.18288)
		(layer "In6.Cu")
		(net "M_D_CPU0_SA_DQ<6>")
	)
	(segment
		(start 286.533844 -309.762144)
		(end 286.020256 -309.762144)
		(width 0.18288)
		(layer "In6.Cu")
		(net "M_D_CPU0_SA_DQ<6>")
	)
	(segment
		(start 332.686914 -277.618444)
		(end 331.883766 -278.421592)
		(width 0.088646)
		(layer "In6.Cu")
		(net "M_D_CPU0_SA_DQ<6>")
	)
	(segment
		(start 330.994766 -278.421592)
		(end 329.093576 -279.20823)
		(width 0.18288)
		(layer "In6.Cu")
		(net "M_D_CPU0_SA_DQ<6>")
	)
	(segment
		(start 275.536152 -309.258462)
		(end 275.536152 -308.951376)
		(width 0.18288)
		(layer "In6.Cu")
		(net "M_D_CPU0_SA_DQ<6>")
	)
	(segment
		(start 276.643846 -309.418482)
		(end 275.696172 -309.418482)
		(width 0.18288)
		(layer "In6.Cu")
		(net "M_D_CPU0_SA_DQ<6>")
	)
	(segment
		(start 313.757564 -294.744394)
		(end 313.318144 -295.183814)
		(width 0.18288)
		(layer "In6.Cu")
		(net "M_D_CPU0_SA_DQ<6>")
	)
	(segment
		(start 270.607536 -308.812438)
		(end 269.533624 -308.812438)
		(width 0.18288)
		(layer "In6.Cu")
		(net "M_D_CPU0_SA_DQ<6>")
	)
	(segment
		(start 345.123262 -274.266914)
		(end 344.56497 -273.835368)
		(width 0.088646)
		(layer "In6.Cu")
		(net "M_D_CPU0_SA_DQ<6>")
	)
	(segment
		(start 313.318144 -295.195244)
		(end 312.068464 -296.444924)
		(width 0.18288)
		(layer "In6.Cu")
		(net "M_D_CPU0_SA_DQ<6>")
	)
	(segment
		(start 298.615354 -303.141634)
		(end 298.455334 -302.981614)
		(width 0.18288)
		(layer "In6.Cu")
		(net "M_D_CPU0_SA_DQ<6>")
	)
	(segment
		(start 283.276294 -309.941976)
		(end 282.988004 -309.653686)
		(width 0.18288)
		(layer "In6.Cu")
		(net "M_D_CPU0_SA_DQ<6>")
	)
	(segment
		(start 303.633378 -300.398942)
		(end 303.633378 -300.812454)
		(width 0.18288)
		(layer "In6.Cu")
		(net "M_D_CPU0_SA_DQ<6>")
	)
	(arc
		(start 343.912952 -273.785076)
		(mid 343.724955 -273.835065)
		(end 343.537286 -273.783806)
		(width 0.088646)
		(layer "In6.Cu")
		(net "M_D_CPU0_SA_DQ<6>")
	)
	(arc
		(start 339.202014 -273.777456)
		(mid 339.014816 -273.827599)
		(end 338.827618 -273.777456)
		(width 0.088646)
		(layer "In6.Cu")
		(net "M_D_CPU0_SA_DQ<6>")
	)
	(arc
		(start 336.85226 -274.591272)
		(mid 336.665062 -274.641415)
		(end 336.477864 -274.591272)
		(width 0.088646)
		(layer "In6.Cu")
		(net "M_D_CPU0_SA_DQ<6>")
	)
	(arc
		(start 342.021414 -273.777456)
		(mid 341.834216 -273.827599)
		(end 341.647018 -273.777456)
		(width 0.088646)
		(layer "In6.Cu")
		(net "M_D_CPU0_SA_DQ<6>")
	)
	(arc
		(start 334.220058 -275.8948)
		(mid 334.172379 -276.0777)
		(end 334.041496 -276.214078)
		(width 0.088646)
		(layer "In6.Cu")
		(net "M_D_CPU0_SA_DQ<6>")
	)
	(arc
		(start 341.081614 -273.777456)
		(mid 340.894416 -273.827599)
		(end 340.707218 -273.777456)
		(width 0.088646)
		(layer "In6.Cu")
		(net "M_D_CPU0_SA_DQ<6>")
	)
	(arc
		(start 335.629758 -275.08073)
		(mid 335.582079 -275.26363)
		(end 335.451196 -275.400008)
		(width 0.088646)
		(layer "In6.Cu")
		(net "M_D_CPU0_SA_DQ<6>")
	)
	(arc
		(start 335.442306 -275.405088)
		(mid 335.255108 -275.455231)
		(end 335.06791 -275.405088)
		(width 0.088646)
		(layer "In6.Cu")
		(net "M_D_CPU0_SA_DQ<6>")
	)
	(arc
		(start 338.827618 -273.777456)
		(mid 338.550805 -273.701586)
		(end 338.272374 -273.77136)
		(width 0.088646)
		(layer "In6.Cu")
		(net "M_D_CPU0_SA_DQ<6>")
	)
	(arc
		(start 338.26196 -273.777456)
		(mid 338.074762 -273.827599)
		(end 337.887564 -273.777456)
		(width 0.088646)
		(layer "In6.Cu")
		(net "M_D_CPU0_SA_DQ<6>")
	)
	(arc
		(start 340.707218 -273.777456)
		(mid 340.433019 -273.701621)
		(end 340.156546 -273.76882)
		(width 0.088646)
		(layer "In6.Cu")
		(net "M_D_CPU0_SA_DQ<6>")
	)
	(arc
		(start 333.643478 -276.210522)
		(mid 333.002911 -276.225205)
		(end 332.686914 -276.78253)
		(width 0.088646)
		(layer "In6.Cu")
		(net "M_D_CPU0_SA_DQ<6>")
	)
	(arc
		(start 342.96096 -273.777456)
		(mid 342.773762 -273.827599)
		(end 342.586564 -273.777456)
		(width 0.088646)
		(layer "In6.Cu")
		(net "M_D_CPU0_SA_DQ<6>")
	)
	(arc
		(start 337.039712 -274.266914)
		(mid 336.992033 -274.449814)
		(end 336.86115 -274.586192)
		(width 0.088646)
		(layer "In6.Cu")
		(net "M_D_CPU0_SA_DQ<6>")
	)
	(arc
		(start 344.481912 -273.7866)
		(mid 344.197643 -273.709087)
		(end 343.912952 -273.785076)
		(width 0.088646)
		(layer "In6.Cu")
		(net "M_D_CPU0_SA_DQ<6>")
	)
	(arc
		(start 339.767418 -273.777456)
		(mid 339.484716 -273.70168)
		(end 339.202014 -273.777456)
		(width 0.088646)
		(layer "In6.Cu")
		(net "M_D_CPU0_SA_DQ<6>")
	)
	(arc
		(start 341.647018 -273.777456)
		(mid 341.372819 -273.701621)
		(end 341.096346 -273.76882)
		(width 0.088646)
		(layer "In6.Cu")
		(net "M_D_CPU0_SA_DQ<6>")
	)
	(arc
		(start 335.900268 -274.598384)
		(mid 335.70204 -274.804232)
		(end 335.629758 -275.08073)
		(width 0.088646)
		(layer "In6.Cu")
		(net "M_D_CPU0_SA_DQ<6>")
	)
	(arc
		(start 340.141814 -273.777456)
		(mid 339.954616 -273.827599)
		(end 339.767418 -273.777456)
		(width 0.088646)
		(layer "In6.Cu")
		(net "M_D_CPU0_SA_DQ<6>")
	)
	(arc
		(start 336.477864 -274.591272)
		(mid 336.195162 -274.515496)
		(end 335.91246 -274.591272)
		(width 0.088646)
		(layer "In6.Cu")
		(net "M_D_CPU0_SA_DQ<6>")
	)
	(arc
		(start 342.586564 -273.777456)
		(mid 342.310005 -273.701713)
		(end 342.031828 -273.77136)
		(width 0.088646)
		(layer "In6.Cu")
		(net "M_D_CPU0_SA_DQ<6>")
	)
	(arc
		(start 337.32216 -273.777456)
		(mid 337.117825 -273.980061)
		(end 337.039712 -274.257008)
		(width 0.088646)
		(layer "In6.Cu")
		(net "M_D_CPU0_SA_DQ<6>")
	)
	(arc
		(start 334.032606 -276.219158)
		(mid 333.845408 -276.269301)
		(end 333.65821 -276.219158)
		(width 0.088646)
		(layer "In6.Cu")
		(net "M_D_CPU0_SA_DQ<6>")
	)
	(arc
		(start 337.887564 -273.777456)
		(mid 337.604862 -273.70168)
		(end 337.32216 -273.777456)
		(width 0.088646)
		(layer "In6.Cu")
		(net "M_D_CPU0_SA_DQ<6>")
	)
	(arc
		(start 334.502506 -275.405088)
		(mid 334.30022 -275.604069)
		(end 334.220058 -275.876258)
		(width 0.088646)
		(layer "In6.Cu")
		(net "M_D_CPU0_SA_DQ<6>")
	)
	(arc
		(start 335.06791 -275.405088)
		(mid 334.785208 -275.329346)
		(end 334.502506 -275.405088)
		(width 0.088646)
		(layer "In6.Cu")
		(net "M_D_CPU0_SA_DQ<6>")
	)
	(arc
		(start 343.511632 -273.76882)
		(mid 343.235157 -273.7015)
		(end 342.96096 -273.777456)
		(width 0.088646)
		(layer "In6.Cu")
		(net "M_D_CPU0_SA_DQ<6>")
	)
	(segment
		(start 258.130548 -308.87797)
		(end 257.626104 -308.87797)
		(width 0.20066)
		(layer "F.Cu")
		(net "M_D_CPU0_SA_DQ<5>")
	)
	(segment
		(start 259.065268 -308.2417)
		(end 259.056378 -308.23281)
		(width 0.1016)
		(layer "F.Cu")
		(net "M_D_CPU0_SA_DQ<5>")
	)
	(segment
		(start 258.28498 -308.723538)
		(end 258.130548 -308.87797)
		(width 0.20066)
		(layer "F.Cu")
		(net "M_D_CPU0_SA_DQ<5>")
	)
	(segment
		(start 258.44754 -308.23281)
		(end 258.28498 -308.39537)
		(width 0.20066)
		(layer "F.Cu")
		(net "M_D_CPU0_SA_DQ<5>")
	)
	(segment
		(start 261.381494 -308.2417)
		(end 261.050786 -308.2417)
		(width 0.101854)
		(layer "F.Cu")
		(net "M_D_CPU0_SA_DQ<5>")
	)
	(segment
		(start 257.414776 -308.666642)
		(end 256.080514 -308.666642)
		(width 0.20066)
		(layer "F.Cu")
		(net "M_D_CPU0_SA_DQ<5>")
	)
	(segment
		(start 259.056378 -308.23281)
		(end 258.44754 -308.23281)
		(width 0.20066)
		(layer "F.Cu")
		(net "M_D_CPU0_SA_DQ<5>")
	)
	(segment
		(start 257.626104 -308.87797)
		(end 257.414776 -308.666642)
		(width 0.20066)
		(layer "F.Cu")
		(net "M_D_CPU0_SA_DQ<5>")
	)
	(segment
		(start 263.624314 -308.666642)
		(end 261.984998 -308.666642)
		(width 0.20066)
		(layer "F.Cu")
		(net "M_D_CPU0_SA_DQ<5>")
	)
	(segment
		(start 261.050786 -308.2417)
		(end 259.065268 -308.2417)
		(width 0.1016)
		(layer "F.Cu")
		(net "M_D_CPU0_SA_DQ<5>")
	)
	(segment
		(start 261.984998 -308.666642)
		(end 261.560056 -308.2417)
		(width 0.20066)
		(layer "F.Cu")
		(net "M_D_CPU0_SA_DQ<5>")
	)
	(segment
		(start 261.560056 -308.2417)
		(end 261.381494 -308.2417)
		(width 0.20066)
		(layer "F.Cu")
		(net "M_D_CPU0_SA_DQ<5>")
	)
	(segment
		(start 264.729214 -308.666642)
		(end 263.624314 -308.666642)
		(width 0.20066)
		(layer "F.Cu")
		(net "M_D_CPU0_SA_DQ<5>")
	)
	(segment
		(start 258.28498 -308.39537)
		(end 258.28498 -308.723538)
		(width 0.20066)
		(layer "F.Cu")
		(net "M_D_CPU0_SA_DQ<5>")
	)
	(arc
		(start 343.713562 -272.917158)
		(mid 343.713625 -273.185128)
		(end 343.713816 -273.453098)
		(width 0.20066)
		(layer "F.Cu")
		(net "M_D_CPU0_SA_DQ<5>")
	)
	(segment
		(start 336.760312 -273.453098)
		(end 336.760312 -273.463004)
		(width 0.088646)
		(layer "In6.Cu")
		(net "M_D_CPU0_SA_DQ<5>")
	)
	(segment
		(start 342.031828 -273.134836)
		(end 342.021414 -273.12874)
		(width 0.088646)
		(layer "In6.Cu")
		(net "M_D_CPU0_SA_DQ<5>")
	)
	(segment
		(start 331.085444 -277.816818)
		(end 328.617326 -278.839168)
		(width 0.18288)
		(layer "In6.Cu")
		(net "M_D_CPU0_SA_DQ<5>")
	)
	(segment
		(start 286.999934 -308.778656)
		(end 286.62249 -308.778656)
		(width 0.18288)
		(layer "In6.Cu")
		(net "M_D_CPU0_SA_DQ<5>")
	)
	(segment
		(start 331.28331 -277.816818)
		(end 331.085444 -277.816818)
		(width 0.18288)
		(layer "In6.Cu")
		(net "M_D_CPU0_SA_DQ<5>")
	)
	(segment
		(start 332.530958 -275.8948)
		(end 332.530958 -275.910294)
		(width 0.088646)
		(layer "In6.Cu")
		(net "M_D_CPU0_SA_DQ<5>")
	)
	(segment
		(start 285.618174 -308.778656)
		(end 285.24073 -308.778656)
		(width 0.18288)
		(layer "In6.Cu")
		(net "M_D_CPU0_SA_DQ<5>")
	)
	(segment
		(start 292.585394 -305.541934)
		(end 291.712142 -306.415186)
		(width 0.18288)
		(layer "In6.Cu")
		(net "M_D_CPU0_SA_DQ<5>")
	)
	(segment
		(start 285.93161 -309.092092)
		(end 285.618174 -308.778656)
		(width 0.18288)
		(layer "In6.Cu")
		(net "M_D_CPU0_SA_DQ<5>")
	)
	(segment
		(start 286.309054 -309.092092)
		(end 285.93161 -309.092092)
		(width 0.18288)
		(layer "In6.Cu")
		(net "M_D_CPU0_SA_DQ<5>")
	)
	(segment
		(start 332.71841 -275.570442)
		(end 332.70952 -275.575522)
		(width 0.088646)
		(layer "In6.Cu")
		(net "M_D_CPU0_SA_DQ<5>")
	)
	(segment
		(start 332.248764 -277.541736)
		(end 331.973682 -277.816818)
		(width 0.088646)
		(layer "In6.Cu")
		(net "M_D_CPU0_SA_DQ<5>")
	)
	(segment
		(start 284.927294 -309.092092)
		(end 281.202892 -309.092092)
		(width 0.18288)
		(layer "In6.Cu")
		(net "M_D_CPU0_SA_DQ<5>")
	)
	(segment
		(start 280.352246 -308.241446)
		(end 268.28369 -308.241446)
		(width 0.18288)
		(layer "In6.Cu")
		(net "M_D_CPU0_SA_DQ<5>")
	)
	(segment
		(start 314.250578 -293.205916)
		(end 313.801252 -293.205916)
		(width 0.18288)
		(layer "In6.Cu")
		(net "M_D_CPU0_SA_DQ<5>")
	)
	(segment
		(start 302.663606 -300.649386)
		(end 302.15967 -300.649386)
		(width 0.18288)
		(layer "In6.Cu")
		(net "M_D_CPU0_SA_DQ<5>")
	)
	(segment
		(start 306.338986 -297.08983)
		(end 304.627788 -298.801028)
		(width 0.18288)
		(layer "In6.Cu")
		(net "M_D_CPU0_SA_DQ<5>")
	)
	(segment
		(start 266.53617 -307.43144)
		(end 266.21105 -307.43144)
		(width 0.18288)
		(layer "In6.Cu")
		(net "M_D_CPU0_SA_DQ<5>")
	)
	(segment
		(start 303.983136 -298.801028)
		(end 303.075848 -299.708316)
		(width 0.18288)
		(layer "In6.Cu")
		(net "M_D_CPU0_SA_DQ<5>")
	)
	(segment
		(start 289.107372 -308.072028)
		(end 288.087308 -309.092092)
		(width 0.18288)
		(layer "In6.Cu")
		(net "M_D_CPU0_SA_DQ<5>")
	)
	(segment
		(start 335.074006 -274.752816)
		(end 335.06791 -274.756372)
		(width 0.088646)
		(layer "In6.Cu")
		(net "M_D_CPU0_SA_DQ<5>")
	)
	(segment
		(start 303.075848 -299.708316)
		(end 303.075848 -300.237144)
		(width 0.18288)
		(layer "In6.Cu")
		(net "M_D_CPU0_SA_DQ<5>")
	)
	(segment
		(start 328.617326 -278.839168)
		(end 314.250578 -293.205916)
		(width 0.18288)
		(layer "In6.Cu")
		(net "M_D_CPU0_SA_DQ<5>")
	)
	(segment
		(start 342.971374 -273.134836)
		(end 342.96096 -273.12874)
		(width 0.088646)
		(layer "In6.Cu")
		(net "M_D_CPU0_SA_DQ<5>")
	)
	(segment
		(start 266.02817 -307.61432)
		(end 266.02817 -308.058566)
		(width 0.18288)
		(layer "In6.Cu")
		(net "M_D_CPU0_SA_DQ<5>")
	)
	(segment
		(start 288.087308 -309.092092)
		(end 287.31337 -309.092092)
		(width 0.18288)
		(layer "In6.Cu")
		(net "M_D_CPU0_SA_DQ<5>")
	)
	(segment
		(start 265.84529 -308.241446)
		(end 265.15441 -308.241446)
		(width 0.18288)
		(layer "In6.Cu")
		(net "M_D_CPU0_SA_DQ<5>")
	)
	(segment
		(start 339.216746 -273.137376)
		(end 339.202014 -273.12874)
		(width 0.088646)
		(layer "In6.Cu")
		(net "M_D_CPU0_SA_DQ<5>")
	)
	(segment
		(start 306.792122 -297.08983)
		(end 306.338986 -297.08983)
		(width 0.18288)
		(layer "In6.Cu")
		(net "M_D_CPU0_SA_DQ<5>")
	)
	(segment
		(start 331.973682 -277.816818)
		(end 331.28331 -277.816818)
		(width 0.088646)
		(layer "In6.Cu")
		(net "M_D_CPU0_SA_DQ<5>")
	)
	(segment
		(start 296.090848 -303.12868)
		(end 296.090848 -303.865534)
		(width 0.18288)
		(layer "In6.Cu")
		(net "M_D_CPU0_SA_DQ<5>")
	)
	(segment
		(start 265.15441 -308.241446)
		(end 264.729214 -308.666642)
		(width 0.18288)
		(layer "In6.Cu")
		(net "M_D_CPU0_SA_DQ<5>")
	)
	(segment
		(start 266.90193 -308.241446)
		(end 266.71905 -308.058566)
		(width 0.18288)
		(layer "In6.Cu")
		(net "M_D_CPU0_SA_DQ<5>")
	)
	(segment
		(start 291.292534 -306.415186)
		(end 289.635692 -308.072028)
		(width 0.18288)
		(layer "In6.Cu")
		(net "M_D_CPU0_SA_DQ<5>")
	)
	(segment
		(start 311.26303 -295.744138)
		(end 308.885082 -295.744138)
		(width 0.18288)
		(layer "In6.Cu")
		(net "M_D_CPU0_SA_DQ<5>")
	)
	(segment
		(start 296.090848 -303.865534)
		(end 295.114726 -304.841656)
		(width 0.18288)
		(layer "In6.Cu")
		(net "M_D_CPU0_SA_DQ<5>")
	)
	(segment
		(start 307.84038 -296.041572)
		(end 306.792122 -297.08983)
		(width 0.18288)
		(layer "In6.Cu")
		(net "M_D_CPU0_SA_DQ<5>")
	)
	(segment
		(start 267.22705 -308.241446)
		(end 266.90193 -308.241446)
		(width 0.18288)
		(layer "In6.Cu")
		(net "M_D_CPU0_SA_DQ<5>")
	)
	(segment
		(start 267.91793 -306.893214)
		(end 267.610336 -306.893214)
		(width 0.18288)
		(layer "In6.Cu")
		(net "M_D_CPU0_SA_DQ<5>")
	)
	(segment
		(start 343.713816 -273.453098)
		(end 344.02649 -273.453098)
		(width 0.088646)
		(layer "In6.Cu")
		(net "M_D_CPU0_SA_DQ<5>")
	)
	(segment
		(start 344.02649 -273.453098)
		(end 344.083894 -273.395694)
		(width 0.088646)
		(layer "In6.Cu")
		(net "M_D_CPU0_SA_DQ<5>")
	)
	(segment
		(start 336.947764 -273.12874)
		(end 336.938874 -273.13382)
		(width 0.088646)
		(layer "In6.Cu")
		(net "M_D_CPU0_SA_DQ<5>")
	)
	(segment
		(start 268.10081 -307.076094)
		(end 267.91793 -306.893214)
		(width 0.18288)
		(layer "In6.Cu")
		(net "M_D_CPU0_SA_DQ<5>")
	)
	(segment
		(start 281.202892 -309.092092)
		(end 280.352246 -308.241446)
		(width 0.18288)
		(layer "In6.Cu")
		(net "M_D_CPU0_SA_DQ<5>")
	)
	(segment
		(start 285.24073 -308.778656)
		(end 284.927294 -309.092092)
		(width 0.18288)
		(layer "In6.Cu")
		(net "M_D_CPU0_SA_DQ<5>")
	)
	(segment
		(start 295.114726 -304.841656)
		(end 294.250872 -304.841656)
		(width 0.18288)
		(layer "In6.Cu")
		(net "M_D_CPU0_SA_DQ<5>")
	)
	(segment
		(start 266.71905 -307.61432)
		(end 266.53617 -307.43144)
		(width 0.18288)
		(layer "In6.Cu")
		(net "M_D_CPU0_SA_DQ<5>")
	)
	(segment
		(start 266.71905 -308.058566)
		(end 266.71905 -307.61432)
		(width 0.18288)
		(layer "In6.Cu")
		(net "M_D_CPU0_SA_DQ<5>")
	)
	(segment
		(start 335.538064 -273.942556)
		(end 335.529174 -273.947636)
		(width 0.088646)
		(layer "In6.Cu")
		(net "M_D_CPU0_SA_DQ<5>")
	)
	(segment
		(start 308.587648 -296.041572)
		(end 307.84038 -296.041572)
		(width 0.18288)
		(layer "In6.Cu")
		(net "M_D_CPU0_SA_DQ<5>")
	)
	(segment
		(start 303.075848 -300.237144)
		(end 302.663606 -300.649386)
		(width 0.18288)
		(layer "In6.Cu")
		(net "M_D_CPU0_SA_DQ<5>")
	)
	(segment
		(start 297.777662 -301.441866)
		(end 296.090848 -303.12868)
		(width 0.18288)
		(layer "In6.Cu")
		(net "M_D_CPU0_SA_DQ<5>")
	)
	(segment
		(start 267.40993 -307.09362)
		(end 267.40993 -308.058566)
		(width 0.18288)
		(layer "In6.Cu")
		(net "M_D_CPU0_SA_DQ<5>")
	)
	(segment
		(start 286.62249 -308.778656)
		(end 286.309054 -309.092092)
		(width 0.18288)
		(layer "In6.Cu")
		(net "M_D_CPU0_SA_DQ<5>")
	)
	(segment
		(start 266.21105 -307.43144)
		(end 266.02817 -307.61432)
		(width 0.18288)
		(layer "In6.Cu")
		(net "M_D_CPU0_SA_DQ<5>")
	)
	(segment
		(start 294.250872 -304.841656)
		(end 293.550594 -305.541934)
		(width 0.18288)
		(layer "In6.Cu")
		(net "M_D_CPU0_SA_DQ<5>")
	)
	(segment
		(start 267.610336 -306.893214)
		(end 267.40993 -307.09362)
		(width 0.18288)
		(layer "In6.Cu")
		(net "M_D_CPU0_SA_DQ<5>")
	)
	(segment
		(start 289.635692 -308.072028)
		(end 289.107372 -308.072028)
		(width 0.18288)
		(layer "In6.Cu")
		(net "M_D_CPU0_SA_DQ<5>")
	)
	(segment
		(start 304.627788 -298.801028)
		(end 303.983136 -298.801028)
		(width 0.18288)
		(layer "In6.Cu")
		(net "M_D_CPU0_SA_DQ<5>")
	)
	(segment
		(start 341.096346 -273.137376)
		(end 341.081614 -273.12874)
		(width 0.088646)
		(layer "In6.Cu")
		(net "M_D_CPU0_SA_DQ<5>")
	)
	(segment
		(start 340.156546 -273.137376)
		(end 340.141814 -273.12874)
		(width 0.088646)
		(layer "In6.Cu")
		(net "M_D_CPU0_SA_DQ<5>")
	)
	(segment
		(start 266.02817 -308.058566)
		(end 265.84529 -308.241446)
		(width 0.18288)
		(layer "In6.Cu")
		(net "M_D_CPU0_SA_DQ<5>")
	)
	(segment
		(start 335.06791 -274.756372)
		(end 335.053178 -274.765008)
		(width 0.088646)
		(layer "In6.Cu")
		(net "M_D_CPU0_SA_DQ<5>")
	)
	(segment
		(start 308.885082 -295.744138)
		(end 308.587648 -296.041572)
		(width 0.18288)
		(layer "In6.Cu")
		(net "M_D_CPU0_SA_DQ<5>")
	)
	(segment
		(start 267.40993 -308.058566)
		(end 267.22705 -308.241446)
		(width 0.18288)
		(layer "In6.Cu")
		(net "M_D_CPU0_SA_DQ<5>")
	)
	(segment
		(start 301.36719 -301.441866)
		(end 297.777662 -301.441866)
		(width 0.18288)
		(layer "In6.Cu")
		(net "M_D_CPU0_SA_DQ<5>")
	)
	(segment
		(start 293.550594 -305.541934)
		(end 292.585394 -305.541934)
		(width 0.18288)
		(layer "In6.Cu")
		(net "M_D_CPU0_SA_DQ<5>")
	)
	(segment
		(start 333.940658 -275.08073)
		(end 333.940658 -275.099272)
		(width 0.088646)
		(layer "In6.Cu")
		(net "M_D_CPU0_SA_DQ<5>")
	)
	(segment
		(start 338.827618 -273.12874)
		(end 338.817204 -273.134836)
		(width 0.088646)
		(layer "In6.Cu")
		(net "M_D_CPU0_SA_DQ<5>")
	)
	(segment
		(start 334.12811 -274.756372)
		(end 334.11922 -274.761452)
		(width 0.088646)
		(layer "In6.Cu")
		(net "M_D_CPU0_SA_DQ<5>")
	)
	(segment
		(start 268.10081 -308.058566)
		(end 268.10081 -307.076094)
		(width 0.18288)
		(layer "In6.Cu")
		(net "M_D_CPU0_SA_DQ<5>")
	)
	(segment
		(start 313.801252 -293.205916)
		(end 311.26303 -295.744138)
		(width 0.18288)
		(layer "In6.Cu")
		(net "M_D_CPU0_SA_DQ<5>")
	)
	(segment
		(start 332.248764 -276.384258)
		(end 332.248764 -277.541736)
		(width 0.088646)
		(layer "In6.Cu")
		(net "M_D_CPU0_SA_DQ<5>")
	)
	(segment
		(start 287.31337 -309.092092)
		(end 286.999934 -308.778656)
		(width 0.18288)
		(layer "In6.Cu")
		(net "M_D_CPU0_SA_DQ<5>")
	)
	(segment
		(start 302.15967 -300.649386)
		(end 301.36719 -301.441866)
		(width 0.18288)
		(layer "In6.Cu")
		(net "M_D_CPU0_SA_DQ<5>")
	)
	(segment
		(start 268.28369 -308.241446)
		(end 268.10081 -308.058566)
		(width 0.18288)
		(layer "In6.Cu")
		(net "M_D_CPU0_SA_DQ<5>")
	)
	(segment
		(start 291.712142 -306.415186)
		(end 291.292534 -306.415186)
		(width 0.18288)
		(layer "In6.Cu")
		(net "M_D_CPU0_SA_DQ<5>")
	)
	(arc
		(start 336.760312 -273.463004)
		(mid 336.682201 -273.739953)
		(end 336.477864 -273.942556)
		(width 0.088646)
		(layer "In6.Cu")
		(net "M_D_CPU0_SA_DQ<5>")
	)
	(arc
		(start 341.081614 -273.12874)
		(mid 340.894416 -273.078597)
		(end 340.707218 -273.12874)
		(width 0.088646)
		(layer "In6.Cu")
		(net "M_D_CPU0_SA_DQ<5>")
	)
	(arc
		(start 337.32216 -273.12874)
		(mid 337.134962 -273.078597)
		(end 336.947764 -273.12874)
		(width 0.088646)
		(layer "In6.Cu")
		(net "M_D_CPU0_SA_DQ<5>")
	)
	(arc
		(start 337.887564 -273.12874)
		(mid 337.604862 -273.204516)
		(end 337.32216 -273.12874)
		(width 0.088646)
		(layer "In6.Cu")
		(net "M_D_CPU0_SA_DQ<5>")
	)
	(arc
		(start 332.530958 -275.910294)
		(mid 332.451588 -276.184028)
		(end 332.248764 -276.384258)
		(width 0.088646)
		(layer "In6.Cu")
		(net "M_D_CPU0_SA_DQ<5>")
	)
	(arc
		(start 338.817204 -273.134836)
		(mid 338.538772 -273.204682)
		(end 338.26196 -273.12874)
		(width 0.088646)
		(layer "In6.Cu")
		(net "M_D_CPU0_SA_DQ<5>")
	)
	(arc
		(start 342.586564 -273.12874)
		(mid 342.310005 -273.204483)
		(end 342.031828 -273.134836)
		(width 0.088646)
		(layer "In6.Cu")
		(net "M_D_CPU0_SA_DQ<5>")
	)
	(arc
		(start 335.053178 -274.765008)
		(mid 334.776703 -274.832328)
		(end 334.502506 -274.756372)
		(width 0.088646)
		(layer "In6.Cu")
		(net "M_D_CPU0_SA_DQ<5>")
	)
	(arc
		(start 339.767418 -273.12874)
		(mid 339.493219 -273.204575)
		(end 339.216746 -273.137376)
		(width 0.088646)
		(layer "In6.Cu")
		(net "M_D_CPU0_SA_DQ<5>")
	)
	(arc
		(start 333.092806 -275.570442)
		(mid 332.905608 -275.520299)
		(end 332.71841 -275.570442)
		(width 0.088646)
		(layer "In6.Cu")
		(net "M_D_CPU0_SA_DQ<5>")
	)
	(arc
		(start 339.202014 -273.12874)
		(mid 339.014816 -273.078597)
		(end 338.827618 -273.12874)
		(width 0.088646)
		(layer "In6.Cu")
		(net "M_D_CPU0_SA_DQ<5>")
	)
	(arc
		(start 333.940658 -275.099272)
		(mid 333.860496 -275.371461)
		(end 333.65821 -275.570442)
		(width 0.088646)
		(layer "In6.Cu")
		(net "M_D_CPU0_SA_DQ<5>")
	)
	(arc
		(start 338.26196 -273.12874)
		(mid 338.074762 -273.078597)
		(end 337.887564 -273.12874)
		(width 0.088646)
		(layer "In6.Cu")
		(net "M_D_CPU0_SA_DQ<5>")
	)
	(arc
		(start 336.938874 -273.13382)
		(mid 336.80796 -273.27018)
		(end 336.760312 -273.453098)
		(width 0.088646)
		(layer "In6.Cu")
		(net "M_D_CPU0_SA_DQ<5>")
	)
	(arc
		(start 344.083894 -273.395694)
		(mid 343.875611 -273.115348)
		(end 343.526618 -273.12874)
		(width 0.088646)
		(layer "In6.Cu")
		(net "M_D_CPU0_SA_DQ<5>")
	)
	(arc
		(start 334.502506 -274.756372)
		(mid 334.315308 -274.706229)
		(end 334.12811 -274.756372)
		(width 0.088646)
		(layer "In6.Cu")
		(net "M_D_CPU0_SA_DQ<5>")
	)
	(arc
		(start 333.65821 -275.570442)
		(mid 333.375508 -275.646184)
		(end 333.092806 -275.570442)
		(width 0.088646)
		(layer "In6.Cu")
		(net "M_D_CPU0_SA_DQ<5>")
	)
	(arc
		(start 334.11922 -274.761452)
		(mid 333.988306 -274.897812)
		(end 333.940658 -275.08073)
		(width 0.088646)
		(layer "In6.Cu")
		(net "M_D_CPU0_SA_DQ<5>")
	)
	(arc
		(start 336.477864 -273.942556)
		(mid 336.195162 -274.018332)
		(end 335.91246 -273.942556)
		(width 0.088646)
		(layer "In6.Cu")
		(net "M_D_CPU0_SA_DQ<5>")
	)
	(arc
		(start 340.707218 -273.12874)
		(mid 340.433019 -273.204575)
		(end 340.156546 -273.137376)
		(width 0.088646)
		(layer "In6.Cu")
		(net "M_D_CPU0_SA_DQ<5>")
	)
	(arc
		(start 342.021414 -273.12874)
		(mid 341.834216 -273.078597)
		(end 341.647018 -273.12874)
		(width 0.088646)
		(layer "In6.Cu")
		(net "M_D_CPU0_SA_DQ<5>")
	)
	(arc
		(start 335.529174 -273.947636)
		(mid 335.39826 -274.083996)
		(end 335.350612 -274.266914)
		(width 0.088646)
		(layer "In6.Cu")
		(net "M_D_CPU0_SA_DQ<5>")
	)
	(arc
		(start 342.96096 -273.12874)
		(mid 342.773762 -273.078597)
		(end 342.586564 -273.12874)
		(width 0.088646)
		(layer "In6.Cu")
		(net "M_D_CPU0_SA_DQ<5>")
	)
	(arc
		(start 343.526618 -273.12874)
		(mid 343.249805 -273.20461)
		(end 342.971374 -273.134836)
		(width 0.088646)
		(layer "In6.Cu")
		(net "M_D_CPU0_SA_DQ<5>")
	)
	(arc
		(start 332.70952 -275.575522)
		(mid 332.578606 -275.711882)
		(end 332.530958 -275.8948)
		(width 0.088646)
		(layer "In6.Cu")
		(net "M_D_CPU0_SA_DQ<5>")
	)
	(arc
		(start 335.350612 -274.266914)
		(mid 335.276621 -274.54648)
		(end 335.074006 -274.752816)
		(width 0.088646)
		(layer "In6.Cu")
		(net "M_D_CPU0_SA_DQ<5>")
	)
	(arc
		(start 335.91246 -273.942556)
		(mid 335.725262 -273.892413)
		(end 335.538064 -273.942556)
		(width 0.088646)
		(layer "In6.Cu")
		(net "M_D_CPU0_SA_DQ<5>")
	)
	(arc
		(start 341.647018 -273.12874)
		(mid 341.372819 -273.204575)
		(end 341.096346 -273.137376)
		(width 0.088646)
		(layer "In6.Cu")
		(net "M_D_CPU0_SA_DQ<5>")
	)
	(arc
		(start 340.141814 -273.12874)
		(mid 339.954616 -273.078597)
		(end 339.767418 -273.12874)
		(width 0.088646)
		(layer "In6.Cu")
		(net "M_D_CPU0_SA_DQ<5>")
	)
	(segment
		(start 257.653536 -310.605424)
		(end 257.414776 -310.366664)
		(width 0.20066)
		(layer "F.Cu")
		(net "M_D_CPU0_SA_DQ<4>")
	)
	(segment
		(start 264.729214 -310.366664)
		(end 263.624314 -310.366664)
		(width 0.20066)
		(layer "F.Cu")
		(net "M_D_CPU0_SA_DQ<4>")
	)
	(segment
		(start 343.243916 -274.26666)
		(end 343.243662 -274.266914)
		(width 0.20066)
		(layer "F.Cu")
		(net "M_D_CPU0_SA_DQ<4>")
	)
	(segment
		(start 261.830312 -309.941722)
		(end 261.381494 -309.941722)
		(width 0.20066)
		(layer "F.Cu")
		(net "M_D_CPU0_SA_DQ<4>")
	)
	(segment
		(start 258.49453 -309.933594)
		(end 258.28498 -310.143144)
		(width 0.20066)
		(layer "F.Cu")
		(net "M_D_CPU0_SA_DQ<4>")
	)
	(segment
		(start 262.255254 -310.366664)
		(end 261.830312 -309.941722)
		(width 0.20066)
		(layer "F.Cu")
		(net "M_D_CPU0_SA_DQ<4>")
	)
	(segment
		(start 261.381494 -309.941722)
		(end 259.31241 -309.941722)
		(width 0.1016)
		(layer "F.Cu")
		(net "M_D_CPU0_SA_DQ<4>")
	)
	(segment
		(start 259.064506 -309.941722)
		(end 259.056378 -309.933594)
		(width 0.101854)
		(layer "F.Cu")
		(net "M_D_CPU0_SA_DQ<4>")
	)
	(segment
		(start 258.28498 -310.432704)
		(end 258.11226 -310.605424)
		(width 0.20066)
		(layer "F.Cu")
		(net "M_D_CPU0_SA_DQ<4>")
	)
	(segment
		(start 258.11226 -310.605424)
		(end 257.653536 -310.605424)
		(width 0.20066)
		(layer "F.Cu")
		(net "M_D_CPU0_SA_DQ<4>")
	)
	(segment
		(start 259.056378 -309.933594)
		(end 258.49453 -309.933594)
		(width 0.20066)
		(layer "F.Cu")
		(net "M_D_CPU0_SA_DQ<4>")
	)
	(segment
		(start 263.624314 -310.366664)
		(end 262.255254 -310.366664)
		(width 0.20066)
		(layer "F.Cu")
		(net "M_D_CPU0_SA_DQ<4>")
	)
	(segment
		(start 257.414776 -310.366664)
		(end 256.080514 -310.366664)
		(width 0.20066)
		(layer "F.Cu")
		(net "M_D_CPU0_SA_DQ<4>")
	)
	(segment
		(start 343.243916 -273.730974)
		(end 343.243916 -274.26666)
		(width 0.20066)
		(layer "F.Cu")
		(net "M_D_CPU0_SA_DQ<4>")
	)
	(segment
		(start 259.31241 -309.941722)
		(end 259.064506 -309.941722)
		(width 0.101854)
		(layer "F.Cu")
		(net "M_D_CPU0_SA_DQ<4>")
	)
	(segment
		(start 258.28498 -310.143144)
		(end 258.28498 -310.432704)
		(width 0.20066)
		(layer "F.Cu")
		(net "M_D_CPU0_SA_DQ<4>")
	)
	(segment
		(start 280.323798 -309.941468)
		(end 273.575526 -309.941468)
		(width 0.18288)
		(layer "In6.Cu")
		(net "M_D_CPU0_SA_DQ<4>")
	)
	(segment
		(start 293.3192 -307.271928)
		(end 292.498272 -307.271928)
		(width 0.18288)
		(layer "In6.Cu")
		(net "M_D_CPU0_SA_DQ<4>")
	)
	(segment
		(start 286.675576 -310.792114)
		(end 286.43961 -311.02808)
		(width 0.18288)
		(layer "In6.Cu")
		(net "M_D_CPU0_SA_DQ<4>")
	)
	(segment
		(start 337.417664 -273.942556)
		(end 337.408774 -273.947636)
		(width 0.088646)
		(layer "In6.Cu")
		(net "M_D_CPU0_SA_DQ<4>")
	)
	(segment
		(start 267.914882 -310.124348)
		(end 267.914882 -311.33034)
		(width 0.18288)
		(layer "In6.Cu")
		(net "M_D_CPU0_SA_DQ<4>")
	)
	(segment
		(start 286.43961 -311.02808)
		(end 286.007556 -311.02808)
		(width 0.18288)
		(layer "In6.Cu")
		(net "M_D_CPU0_SA_DQ<4>")
	)
	(segment
		(start 306.413662 -298.739306)
		(end 305.024536 -300.128432)
		(width 0.18288)
		(layer "In6.Cu")
		(net "M_D_CPU0_SA_DQ<4>")
	)
	(segment
		(start 281.372056 -310.792114)
		(end 281.034744 -310.652414)
		(width 0.18288)
		(layer "In6.Cu")
		(net "M_D_CPU0_SA_DQ<4>")
	)
	(segment
		(start 267.224002 -311.33034)
		(end 267.224002 -310.124348)
		(width 0.18288)
		(layer "In6.Cu")
		(net "M_D_CPU0_SA_DQ<4>")
	)
	(segment
		(start 302.85436 -302.509682)
		(end 301.824898 -302.509682)
		(width 0.18288)
		(layer "In6.Cu")
		(net "M_D_CPU0_SA_DQ<4>")
	)
	(segment
		(start 336.007964 -274.756372)
		(end 335.999074 -274.761452)
		(width 0.088646)
		(layer "In6.Cu")
		(net "M_D_CPU0_SA_DQ<4>")
	)
	(segment
		(start 315.378846 -294.443404)
		(end 314.538868 -295.283382)
		(width 0.18288)
		(layer "In6.Cu")
		(net "M_D_CPU0_SA_DQ<4>")
	)
	(segment
		(start 267.406882 -311.51322)
		(end 267.224002 -311.33034)
		(width 0.18288)
		(layer "In6.Cu")
		(net "M_D_CPU0_SA_DQ<4>")
	)
	(segment
		(start 309.005224 -297.226228)
		(end 308.310788 -297.920664)
		(width 0.18288)
		(layer "In6.Cu")
		(net "M_D_CPU0_SA_DQ<4>")
	)
	(segment
		(start 272.782284 -310.73471)
		(end 270.199358 -310.73471)
		(width 0.18288)
		(layer "In6.Cu")
		(net "M_D_CPU0_SA_DQ<4>")
	)
	(segment
		(start 281.034744 -310.652414)
		(end 280.323798 -309.941468)
		(width 0.18288)
		(layer "In6.Cu")
		(net "M_D_CPU0_SA_DQ<4>")
	)
	(segment
		(start 270.199358 -310.73471)
		(end 269.406116 -309.941468)
		(width 0.18288)
		(layer "In6.Cu")
		(net "M_D_CPU0_SA_DQ<4>")
	)
	(segment
		(start 268.097762 -309.941468)
		(end 267.914882 -310.124348)
		(width 0.18288)
		(layer "In6.Cu")
		(net "M_D_CPU0_SA_DQ<4>")
	)
	(segment
		(start 333.577692 -276.392894)
		(end 333.56296 -276.384258)
		(width 0.088646)
		(layer "In6.Cu")
		(net "M_D_CPU0_SA_DQ<4>")
	)
	(segment
		(start 297.426634 -304.739294)
		(end 296.67835 -304.739294)
		(width 0.18288)
		(layer "In6.Cu")
		(net "M_D_CPU0_SA_DQ<4>")
	)
	(segment
		(start 331.436726 -278.93645)
		(end 331.16774 -278.93645)
		(width 0.18288)
		(layer "In6.Cu")
		(net "M_D_CPU0_SA_DQ<4>")
	)
	(segment
		(start 343.243662 -274.266914)
		(end 342.872568 -274.166076)
		(width 0.088646)
		(layer "In6.Cu")
		(net "M_D_CPU0_SA_DQ<4>")
	)
	(segment
		(start 334.410558 -275.8948)
		(end 334.410558 -275.910294)
		(width 0.088646)
		(layer "In6.Cu")
		(net "M_D_CPU0_SA_DQ<4>")
	)
	(segment
		(start 304.46091 -301.597822)
		(end 303.76622 -301.597822)
		(width 0.18288)
		(layer "In6.Cu")
		(net "M_D_CPU0_SA_DQ<4>")
	)
	(segment
		(start 339.297518 -273.942556)
		(end 339.287104 -273.948652)
		(width 0.088646)
		(layer "In6.Cu")
		(net "M_D_CPU0_SA_DQ<4>")
	)
	(segment
		(start 292.498272 -307.271928)
		(end 291.642292 -308.127908)
		(width 0.18288)
		(layer "In6.Cu")
		(net "M_D_CPU0_SA_DQ<4>")
	)
	(segment
		(start 282.449524 -310.792114)
		(end 281.372056 -310.792114)
		(width 0.18288)
		(layer "In6.Cu")
		(net "M_D_CPU0_SA_DQ<4>")
	)
	(segment
		(start 308.310788 -297.920664)
		(end 307.648102 -297.920664)
		(width 0.18288)
		(layer "In6.Cu")
		(net "M_D_CPU0_SA_DQ<4>")
	)
	(segment
		(start 311.146698 -297.114722)
		(end 311.035192 -297.226228)
		(width 0.18288)
		(layer "In6.Cu")
		(net "M_D_CPU0_SA_DQ<4>")
	)
	(segment
		(start 331.638148 -278.93645)
		(end 331.436726 -278.93645)
		(width 0.088646)
		(layer "In6.Cu")
		(net "M_D_CPU0_SA_DQ<4>")
	)
	(segment
		(start 283.462984 -310.792114)
		(end 283.302964 -310.952134)
		(width 0.18288)
		(layer "In6.Cu")
		(net "M_D_CPU0_SA_DQ<4>")
	)
	(segment
		(start 300.342808 -303.991772)
		(end 298.174156 -303.991772)
		(width 0.18288)
		(layer "In6.Cu")
		(net "M_D_CPU0_SA_DQ<4>")
	)
	(segment
		(start 288.955988 -309.808372)
		(end 287.972246 -310.792114)
		(width 0.18288)
		(layer "In6.Cu")
		(net "M_D_CPU0_SA_DQ<4>")
	)
	(segment
		(start 267.224002 -310.124348)
		(end 267.041122 -309.941468)
		(width 0.18288)
		(layer "In6.Cu")
		(net "M_D_CPU0_SA_DQ<4>")
	)
	(segment
		(start 341.176864 -273.942556)
		(end 341.162132 -273.951192)
		(width 0.088646)
		(layer "In6.Cu")
		(net "M_D_CPU0_SA_DQ<4>")
	)
	(segment
		(start 313.973972 -295.283382)
		(end 312.142632 -297.114722)
		(width 0.18288)
		(layer "In6.Cu")
		(net "M_D_CPU0_SA_DQ<4>")
	)
	(segment
		(start 273.575526 -309.941468)
		(end 272.782284 -310.73471)
		(width 0.18288)
		(layer "In6.Cu")
		(net "M_D_CPU0_SA_DQ<4>")
	)
	(segment
		(start 314.538868 -295.283382)
		(end 313.973972 -295.283382)
		(width 0.18288)
		(layer "In6.Cu")
		(net "M_D_CPU0_SA_DQ<4>")
	)
	(segment
		(start 291.642292 -308.127908)
		(end 291.351208 -308.127908)
		(width 0.18288)
		(layer "In6.Cu")
		(net "M_D_CPU0_SA_DQ<4>")
	)
	(segment
		(start 296.67835 -304.739294)
		(end 296.217848 -305.199796)
		(width 0.18288)
		(layer "In6.Cu")
		(net "M_D_CPU0_SA_DQ<4>")
	)
	(segment
		(start 267.732002 -311.51322)
		(end 267.406882 -311.51322)
		(width 0.18288)
		(layer "In6.Cu")
		(net "M_D_CPU0_SA_DQ<4>")
	)
	(segment
		(start 342.116664 -273.942556)
		(end 342.101932 -273.951192)
		(width 0.088646)
		(layer "In6.Cu")
		(net "M_D_CPU0_SA_DQ<4>")
	)
	(segment
		(start 295.345358 -306.541678)
		(end 294.04945 -306.541678)
		(width 0.18288)
		(layer "In6.Cu")
		(net "M_D_CPU0_SA_DQ<4>")
	)
	(segment
		(start 267.914882 -311.33034)
		(end 267.732002 -311.51322)
		(width 0.18288)
		(layer "In6.Cu")
		(net "M_D_CPU0_SA_DQ<4>")
	)
	(segment
		(start 340.237064 -273.942556)
		(end 340.22665 -273.948652)
		(width 0.088646)
		(layer "In6.Cu")
		(net "M_D_CPU0_SA_DQ<4>")
	)
	(segment
		(start 315.378846 -293.659306)
		(end 315.378846 -294.443404)
		(width 0.18288)
		(layer "In6.Cu")
		(net "M_D_CPU0_SA_DQ<4>")
	)
	(segment
		(start 329.34783 -279.690322)
		(end 315.378846 -293.659306)
		(width 0.18288)
		(layer "In6.Cu")
		(net "M_D_CPU0_SA_DQ<4>")
	)
	(segment
		(start 283.302964 -311.1627)
		(end 283.142944 -311.32272)
		(width 0.18288)
		(layer "In6.Cu")
		(net "M_D_CPU0_SA_DQ<4>")
	)
	(segment
		(start 331.16774 -278.93645)
		(end 329.34783 -279.690322)
		(width 0.18288)
		(layer "In6.Cu")
		(net "M_D_CPU0_SA_DQ<4>")
	)
	(segment
		(start 333.256636 -276.424644)
		(end 332.87716 -276.80412)
		(width 0.088646)
		(layer "In6.Cu")
		(net "M_D_CPU0_SA_DQ<4>")
	)
	(segment
		(start 334.59801 -275.570442)
		(end 334.58912 -275.575522)
		(width 0.088646)
		(layer "In6.Cu")
		(net "M_D_CPU0_SA_DQ<4>")
	)
	(segment
		(start 285.77159 -310.792114)
		(end 283.462984 -310.792114)
		(width 0.18288)
		(layer "In6.Cu")
		(net "M_D_CPU0_SA_DQ<4>")
	)
	(segment
		(start 342.872568 -274.166076)
		(end 342.49106 -273.942556)
		(width 0.088646)
		(layer "In6.Cu")
		(net "M_D_CPU0_SA_DQ<4>")
	)
	(segment
		(start 298.174156 -303.991772)
		(end 297.426634 -304.739294)
		(width 0.18288)
		(layer "In6.Cu")
		(net "M_D_CPU0_SA_DQ<4>")
	)
	(segment
		(start 265.15441 -309.941468)
		(end 264.729214 -310.366664)
		(width 0.18288)
		(layer "In6.Cu")
		(net "M_D_CPU0_SA_DQ<4>")
	)
	(segment
		(start 296.217848 -305.199796)
		(end 296.217848 -305.669188)
		(width 0.18288)
		(layer "In6.Cu")
		(net "M_D_CPU0_SA_DQ<4>")
	)
	(segment
		(start 305.024536 -300.128432)
		(end 305.024536 -301.034196)
		(width 0.18288)
		(layer "In6.Cu")
		(net "M_D_CPU0_SA_DQ<4>")
	)
	(segment
		(start 282.609544 -311.1627)
		(end 282.609544 -310.952134)
		(width 0.18288)
		(layer "In6.Cu")
		(net "M_D_CPU0_SA_DQ<4>")
	)
	(segment
		(start 301.824898 -302.509682)
		(end 300.342808 -303.991772)
		(width 0.18288)
		(layer "In6.Cu")
		(net "M_D_CPU0_SA_DQ<4>")
	)
	(segment
		(start 286.007556 -311.02808)
		(end 285.77159 -310.792114)
		(width 0.18288)
		(layer "In6.Cu")
		(net "M_D_CPU0_SA_DQ<4>")
	)
	(segment
		(start 305.024536 -301.034196)
		(end 304.46091 -301.597822)
		(width 0.18288)
		(layer "In6.Cu")
		(net "M_D_CPU0_SA_DQ<4>")
	)
	(segment
		(start 269.406116 -309.941468)
		(end 268.097762 -309.941468)
		(width 0.18288)
		(layer "In6.Cu")
		(net "M_D_CPU0_SA_DQ<4>")
	)
	(segment
		(start 335.820512 -275.08073)
		(end 335.820512 -275.08835)
		(width 0.088646)
		(layer "In6.Cu")
		(net "M_D_CPU0_SA_DQ<4>")
	)
	(segment
		(start 283.142944 -311.32272)
		(end 282.769564 -311.32272)
		(width 0.18288)
		(layer "In6.Cu")
		(net "M_D_CPU0_SA_DQ<4>")
	)
	(segment
		(start 332.87716 -276.80412)
		(end 332.87716 -277.697438)
		(width 0.088646)
		(layer "In6.Cu")
		(net "M_D_CPU0_SA_DQ<4>")
	)
	(segment
		(start 283.302964 -310.952134)
		(end 283.302964 -311.1627)
		(width 0.18288)
		(layer "In6.Cu")
		(net "M_D_CPU0_SA_DQ<4>")
	)
	(segment
		(start 332.87716 -277.697438)
		(end 331.638148 -278.93645)
		(width 0.088646)
		(layer "In6.Cu")
		(net "M_D_CPU0_SA_DQ<4>")
	)
	(segment
		(start 312.142632 -297.114722)
		(end 311.146698 -297.114722)
		(width 0.18288)
		(layer "In6.Cu")
		(net "M_D_CPU0_SA_DQ<4>")
	)
	(segment
		(start 282.769564 -311.32272)
		(end 282.609544 -311.1627)
		(width 0.18288)
		(layer "In6.Cu")
		(net "M_D_CPU0_SA_DQ<4>")
	)
	(segment
		(start 287.972246 -310.792114)
		(end 286.675576 -310.792114)
		(width 0.18288)
		(layer "In6.Cu")
		(net "M_D_CPU0_SA_DQ<4>")
	)
	(segment
		(start 303.76622 -301.597822)
		(end 302.85436 -302.509682)
		(width 0.18288)
		(layer "In6.Cu")
		(net "M_D_CPU0_SA_DQ<4>")
	)
	(segment
		(start 307.648102 -297.920664)
		(end 306.82946 -298.739306)
		(width 0.18288)
		(layer "In6.Cu")
		(net "M_D_CPU0_SA_DQ<4>")
	)
	(segment
		(start 337.230212 -274.266914)
		(end 337.230212 -274.27682)
		(width 0.088646)
		(layer "In6.Cu")
		(net "M_D_CPU0_SA_DQ<4>")
	)
	(segment
		(start 282.609544 -310.952134)
		(end 282.449524 -310.792114)
		(width 0.18288)
		(layer "In6.Cu")
		(net "M_D_CPU0_SA_DQ<4>")
	)
	(segment
		(start 291.351208 -308.127908)
		(end 289.670744 -309.808372)
		(width 0.18288)
		(layer "In6.Cu")
		(net "M_D_CPU0_SA_DQ<4>")
	)
	(segment
		(start 294.04945 -306.541678)
		(end 293.3192 -307.271928)
		(width 0.18288)
		(layer "In6.Cu")
		(net "M_D_CPU0_SA_DQ<4>")
	)
	(segment
		(start 296.217848 -305.669188)
		(end 295.345358 -306.541678)
		(width 0.18288)
		(layer "In6.Cu")
		(net "M_D_CPU0_SA_DQ<4>")
	)
	(segment
		(start 311.035192 -297.226228)
		(end 309.005224 -297.226228)
		(width 0.18288)
		(layer "In6.Cu")
		(net "M_D_CPU0_SA_DQ<4>")
	)
	(segment
		(start 306.82946 -298.739306)
		(end 306.413662 -298.739306)
		(width 0.18288)
		(layer "In6.Cu")
		(net "M_D_CPU0_SA_DQ<4>")
	)
	(segment
		(start 267.041122 -309.941468)
		(end 265.15441 -309.941468)
		(width 0.18288)
		(layer "In6.Cu")
		(net "M_D_CPU0_SA_DQ<4>")
	)
	(segment
		(start 289.670744 -309.808372)
		(end 288.955988 -309.808372)
		(width 0.18288)
		(layer "In6.Cu")
		(net "M_D_CPU0_SA_DQ<4>")
	)
	(arc
		(start 335.820512 -275.08835)
		(mid 335.742883 -275.366763)
		(end 335.53781 -275.570442)
		(width 0.088646)
		(layer "In6.Cu")
		(net "M_D_CPU0_SA_DQ<4>")
	)
	(arc
		(start 335.999074 -274.761452)
		(mid 335.86816 -274.897812)
		(end 335.820512 -275.08073)
		(width 0.088646)
		(layer "In6.Cu")
		(net "M_D_CPU0_SA_DQ<4>")
	)
	(arc
		(start 334.972406 -275.570442)
		(mid 334.785208 -275.520299)
		(end 334.59801 -275.570442)
		(width 0.088646)
		(layer "In6.Cu")
		(net "M_D_CPU0_SA_DQ<4>")
	)
	(arc
		(start 342.49106 -273.942556)
		(mid 342.303862 -273.892413)
		(end 342.116664 -273.942556)
		(width 0.088646)
		(layer "In6.Cu")
		(net "M_D_CPU0_SA_DQ<4>")
	)
	(arc
		(start 338.73186 -273.942556)
		(mid 338.544662 -273.892413)
		(end 338.357464 -273.942556)
		(width 0.088646)
		(layer "In6.Cu")
		(net "M_D_CPU0_SA_DQ<4>")
	)
	(arc
		(start 337.230212 -274.27682)
		(mid 337.152101 -274.553769)
		(end 336.947764 -274.756372)
		(width 0.088646)
		(layer "In6.Cu")
		(net "M_D_CPU0_SA_DQ<4>")
	)
	(arc
		(start 340.61146 -273.942556)
		(mid 340.424262 -273.892413)
		(end 340.237064 -273.942556)
		(width 0.088646)
		(layer "In6.Cu")
		(net "M_D_CPU0_SA_DQ<4>")
	)
	(arc
		(start 337.79206 -273.942556)
		(mid 337.604862 -273.892413)
		(end 337.417664 -273.942556)
		(width 0.088646)
		(layer "In6.Cu")
		(net "M_D_CPU0_SA_DQ<4>")
	)
	(arc
		(start 334.128364 -276.384258)
		(mid 333.854165 -276.460093)
		(end 333.577692 -276.392894)
		(width 0.088646)
		(layer "In6.Cu")
		(net "M_D_CPU0_SA_DQ<4>")
	)
	(arc
		(start 342.101932 -273.951192)
		(mid 341.825457 -274.018512)
		(end 341.55126 -273.942556)
		(width 0.088646)
		(layer "In6.Cu")
		(net "M_D_CPU0_SA_DQ<4>")
	)
	(arc
		(start 336.38236 -274.756372)
		(mid 336.195162 -274.706229)
		(end 336.007964 -274.756372)
		(width 0.088646)
		(layer "In6.Cu")
		(net "M_D_CPU0_SA_DQ<4>")
	)
	(arc
		(start 339.671914 -273.942556)
		(mid 339.484716 -273.892413)
		(end 339.297518 -273.942556)
		(width 0.088646)
		(layer "In6.Cu")
		(net "M_D_CPU0_SA_DQ<4>")
	)
	(arc
		(start 333.56296 -276.384258)
		(mid 333.402973 -276.352508)
		(end 333.256636 -276.424644)
		(width 0.088646)
		(layer "In6.Cu")
		(net "M_D_CPU0_SA_DQ<4>")
	)
	(arc
		(start 341.162132 -273.951192)
		(mid 340.885657 -274.018512)
		(end 340.61146 -273.942556)
		(width 0.088646)
		(layer "In6.Cu")
		(net "M_D_CPU0_SA_DQ<4>")
	)
	(arc
		(start 334.58912 -275.575522)
		(mid 334.458206 -275.711882)
		(end 334.410558 -275.8948)
		(width 0.088646)
		(layer "In6.Cu")
		(net "M_D_CPU0_SA_DQ<4>")
	)
	(arc
		(start 336.947764 -274.756372)
		(mid 336.665062 -274.832148)
		(end 336.38236 -274.756372)
		(width 0.088646)
		(layer "In6.Cu")
		(net "M_D_CPU0_SA_DQ<4>")
	)
	(arc
		(start 337.408774 -273.947636)
		(mid 337.27786 -274.083996)
		(end 337.230212 -274.266914)
		(width 0.088646)
		(layer "In6.Cu")
		(net "M_D_CPU0_SA_DQ<4>")
	)
	(arc
		(start 339.287104 -273.948652)
		(mid 339.008672 -274.018498)
		(end 338.73186 -273.942556)
		(width 0.088646)
		(layer "In6.Cu")
		(net "M_D_CPU0_SA_DQ<4>")
	)
	(arc
		(start 341.55126 -273.942556)
		(mid 341.364062 -273.892413)
		(end 341.176864 -273.942556)
		(width 0.088646)
		(layer "In6.Cu")
		(net "M_D_CPU0_SA_DQ<4>")
	)
	(arc
		(start 334.410558 -275.910294)
		(mid 334.331188 -276.184028)
		(end 334.128364 -276.384258)
		(width 0.088646)
		(layer "In6.Cu")
		(net "M_D_CPU0_SA_DQ<4>")
	)
	(arc
		(start 338.357464 -273.942556)
		(mid 338.074762 -274.018332)
		(end 337.79206 -273.942556)
		(width 0.088646)
		(layer "In6.Cu")
		(net "M_D_CPU0_SA_DQ<4>")
	)
	(arc
		(start 340.22665 -273.948652)
		(mid 339.948472 -274.018375)
		(end 339.671914 -273.942556)
		(width 0.088646)
		(layer "In6.Cu")
		(net "M_D_CPU0_SA_DQ<4>")
	)
	(arc
		(start 335.53781 -275.570442)
		(mid 335.255108 -275.646184)
		(end 334.972406 -275.570442)
		(width 0.088646)
		(layer "In6.Cu")
		(net "M_D_CPU0_SA_DQ<4>")
	)
	(segment
		(start 266.700762 -313.974226)
		(end 266.25423 -313.974226)
		(width 0.20066)
		(layer "F.Cu")
		(net "M_D_CPU0_SA_DQ<3>")
	)
	(segment
		(start 266.042394 -313.76239)
		(end 265.64717 -313.76239)
		(width 0.20066)
		(layer "F.Cu")
		(net "M_D_CPU0_SA_DQ<3>")
	)
	(segment
		(start 262.003794 -313.892692)
		(end 261.87781 -313.766708)
		(width 0.20066)
		(layer "F.Cu")
		(net "M_D_CPU0_SA_DQ<3>")
	)
	(segment
		(start 265.64717 -313.76239)
		(end 265.518646 -313.890914)
		(width 0.20066)
		(layer "F.Cu")
		(net "M_D_CPU0_SA_DQ<3>")
	)
	(segment
		(start 264.825226 -314.19165)
		(end 262.752332 -314.19165)
		(width 0.1016)
		(layer "F.Cu")
		(net "M_D_CPU0_SA_DQ<3>")
	)
	(segment
		(start 265.518646 -314.042552)
		(end 265.369548 -314.19165)
		(width 0.20066)
		(layer "F.Cu")
		(net "M_D_CPU0_SA_DQ<3>")
	)
	(segment
		(start 267.724382 -313.766708)
		(end 266.90828 -313.766708)
		(width 0.20066)
		(layer "F.Cu")
		(net "M_D_CPU0_SA_DQ<3>")
	)
	(segment
		(start 266.25423 -313.974226)
		(end 266.042394 -313.76239)
		(width 0.20066)
		(layer "F.Cu")
		(net "M_D_CPU0_SA_DQ<3>")
	)
	(segment
		(start 261.87781 -313.766708)
		(end 260.180582 -313.766708)
		(width 0.20066)
		(layer "F.Cu")
		(net "M_D_CPU0_SA_DQ<3>")
	)
	(segment
		(start 262.514334 -314.19165)
		(end 262.50011 -314.205874)
		(width 0.101854)
		(layer "F.Cu")
		(net "M_D_CPU0_SA_DQ<3>")
	)
	(segment
		(start 265.518646 -313.890914)
		(end 265.518646 -314.042552)
		(width 0.20066)
		(layer "F.Cu")
		(net "M_D_CPU0_SA_DQ<3>")
	)
	(segment
		(start 262.752332 -314.19165)
		(end 262.514334 -314.19165)
		(width 0.101854)
		(layer "F.Cu")
		(net "M_D_CPU0_SA_DQ<3>")
	)
	(segment
		(start 268.829282 -313.766708)
		(end 267.724382 -313.766708)
		(width 0.20066)
		(layer "F.Cu")
		(net "M_D_CPU0_SA_DQ<3>")
	)
	(segment
		(start 266.90828 -313.766708)
		(end 266.700762 -313.974226)
		(width 0.20066)
		(layer "F.Cu")
		(net "M_D_CPU0_SA_DQ<3>")
	)
	(segment
		(start 262.003794 -314.06338)
		(end 262.003794 -313.892692)
		(width 0.20066)
		(layer "F.Cu")
		(net "M_D_CPU0_SA_DQ<3>")
	)
	(segment
		(start 265.369548 -314.19165)
		(end 264.825226 -314.19165)
		(width 0.20066)
		(layer "F.Cu")
		(net "M_D_CPU0_SA_DQ<3>")
	)
	(segment
		(start 262.50011 -314.205874)
		(end 262.146288 -314.205874)
		(width 0.20066)
		(layer "F.Cu")
		(net "M_D_CPU0_SA_DQ<3>")
	)
	(segment
		(start 262.146288 -314.205874)
		(end 262.003794 -314.06338)
		(width 0.20066)
		(layer "F.Cu")
		(net "M_D_CPU0_SA_DQ<3>")
	)
	(arc
		(start 345.123516 -275.35886)
		(mid 345.123452 -275.62683)
		(end 345.123262 -275.8948)
		(width 0.20066)
		(layer "F.Cu")
		(net "M_D_CPU0_SA_DQ<3>")
	)
	(segment
		(start 292.038786 -311.935368)
		(end 290.481004 -312.580528)
		(width 0.18288)
		(layer "In6.Cu")
		(net "M_D_CPU0_SA_DQ<3>")
	)
	(segment
		(start 306.638706 -304.169826)
		(end 306.072794 -304.169826)
		(width 0.18288)
		(layer "In6.Cu")
		(net "M_D_CPU0_SA_DQ<3>")
	)
	(segment
		(start 297.814492 -309.29834)
		(end 297.550078 -309.562754)
		(width 0.18288)
		(layer "In6.Cu")
		(net "M_D_CPU0_SA_DQ<3>")
	)
	(segment
		(start 289.613086 -313.448446)
		(end 288.492184 -313.448446)
		(width 0.18288)
		(layer "In6.Cu")
		(net "M_D_CPU0_SA_DQ<3>")
	)
	(segment
		(start 300.507654 -308.2417)
		(end 297.953684 -308.2417)
		(width 0.18288)
		(layer "In6.Cu")
		(net "M_D_CPU0_SA_DQ<3>")
	)
	(segment
		(start 275.519642 -313.085734)
		(end 275.336762 -312.902854)
		(width 0.18288)
		(layer "In6.Cu")
		(net "M_D_CPU0_SA_DQ<3>")
	)
	(segment
		(start 338.26196 -277.032974)
		(end 338.255864 -277.03653)
		(width 0.088646)
		(layer "In6.Cu")
		(net "M_D_CPU0_SA_DQ<3>")
	)
	(segment
		(start 341.176864 -276.219158)
		(end 341.162132 -276.210522)
		(width 0.088646)
		(layer "In6.Cu")
		(net "M_D_CPU0_SA_DQ<3>")
	)
	(segment
		(start 297.550078 -309.562754)
		(end 297.324018 -309.562754)
		(width 0.18288)
		(layer "In6.Cu")
		(net "M_D_CPU0_SA_DQ<3>")
	)
	(segment
		(start 334.220312 -279.140412)
		(end 334.220312 -279.150318)
		(width 0.088646)
		(layer "In6.Cu")
		(net "M_D_CPU0_SA_DQ<3>")
	)
	(segment
		(start 272.589244 -314.355226)
		(end 271.698974 -314.355226)
		(width 0.18288)
		(layer "In6.Cu")
		(net "M_D_CPU0_SA_DQ<3>")
	)
	(segment
		(start 333.1718 -281.294332)
		(end 332.987396 -281.478736)
		(width 0.088646)
		(layer "In6.Cu")
		(net "M_D_CPU0_SA_DQ<3>")
	)
	(segment
		(start 338.27085 -277.027894)
		(end 338.26196 -277.032974)
		(width 0.088646)
		(layer "In6.Cu")
		(net "M_D_CPU0_SA_DQ<3>")
	)
	(segment
		(start 308.982364 -301.441612)
		(end 307.227224 -303.196752)
		(width 0.18288)
		(layer "In6.Cu")
		(net "M_D_CPU0_SA_DQ<3>")
	)
	(segment
		(start 271.008094 -313.649614)
		(end 270.825214 -313.832494)
		(width 0.18288)
		(layer "In6.Cu")
		(net "M_D_CPU0_SA_DQ<3>")
	)
	(segment
		(start 282.062936 -315.041534)
		(end 279.481788 -315.041534)
		(width 0.18288)
		(layer "In6.Cu")
		(net "M_D_CPU0_SA_DQ<3>")
	)
	(segment
		(start 295.403524 -310.79186)
		(end 293.988744 -310.79186)
		(width 0.18288)
		(layer "In6.Cu")
		(net "M_D_CPU0_SA_DQ<3>")
	)
	(segment
		(start 312.244994 -301.93488)
		(end 311.620916 -301.93488)
		(width 0.18288)
		(layer "In6.Cu")
		(net "M_D_CPU0_SA_DQ<3>")
	)
	(segment
		(start 279.481788 -315.041534)
		(end 278.849074 -314.40882)
		(width 0.18288)
		(layer "In6.Cu")
		(net "M_D_CPU0_SA_DQ<3>")
	)
	(segment
		(start 303.486566 -305.92014)
		(end 302.669702 -306.737004)
		(width 0.18288)
		(layer "In6.Cu")
		(net "M_D_CPU0_SA_DQ<3>")
	)
	(segment
		(start 338.449412 -276.69871)
		(end 338.449412 -276.708616)
		(width 0.088646)
		(layer "In6.Cu")
		(net "M_D_CPU0_SA_DQ<3>")
	)
	(segment
		(start 275.519642 -313.41441)
		(end 275.519642 -313.085734)
		(width 0.18288)
		(layer "In6.Cu")
		(net "M_D_CPU0_SA_DQ<3>")
	)
	(segment
		(start 270.825214 -313.832494)
		(end 270.825214 -314.172346)
		(width 0.18288)
		(layer "In6.Cu")
		(net "M_D_CPU0_SA_DQ<3>")
	)
	(segment
		(start 342.116918 -276.219158)
		(end 342.106504 -276.213062)
		(width 0.088646)
		(layer "In6.Cu")
		(net "M_D_CPU0_SA_DQ<3>")
	)
	(segment
		(start 337.509612 -278.31796)
		(end 337.509612 -278.336502)
		(width 0.088646)
		(layer "In6.Cu")
		(net "M_D_CPU0_SA_DQ<3>")
	)
	(segment
		(start 342.491822 -276.218904)
		(end 342.491314 -276.219158)
		(width 0.088646)
		(layer "In6.Cu")
		(net "M_D_CPU0_SA_DQ<3>")
	)
	(segment
		(start 286.966152 -314.378848)
		(end 285.453582 -315.891418)
		(width 0.18288)
		(layer "In6.Cu")
		(net "M_D_CPU0_SA_DQ<3>")
	)
	(segment
		(start 297.091354 -309.33009)
		(end 296.865294 -309.33009)
		(width 0.18288)
		(layer "In6.Cu")
		(net "M_D_CPU0_SA_DQ<3>")
	)
	(segment
		(start 271.516094 -314.172346)
		(end 271.516094 -313.832494)
		(width 0.18288)
		(layer "In6.Cu")
		(net "M_D_CPU0_SA_DQ<3>")
	)
	(segment
		(start 344.788998 -275.806916)
		(end 344.365072 -275.56714)
		(width 0.088646)
		(layer "In6.Cu")
		(net "M_D_CPU0_SA_DQ<3>")
	)
	(segment
		(start 275.011642 -312.902854)
		(end 274.828762 -313.085734)
		(width 0.18288)
		(layer "In6.Cu")
		(net "M_D_CPU0_SA_DQ<3>")
	)
	(segment
		(start 297.953684 -308.2417)
		(end 297.581828 -308.613556)
		(width 0.18288)
		(layer "In6.Cu")
		(net "M_D_CPU0_SA_DQ<3>")
	)
	(segment
		(start 302.669702 -306.737004)
		(end 302.01235 -306.737004)
		(width 0.18288)
		(layer "In6.Cu")
		(net "M_D_CPU0_SA_DQ<3>")
	)
	(segment
		(start 293.988744 -310.79186)
		(end 292.845236 -311.935368)
		(width 0.18288)
		(layer "In6.Cu")
		(net "M_D_CPU0_SA_DQ<3>")
	)
	(segment
		(start 337.80095 -277.84171)
		(end 337.79206 -277.84679)
		(width 0.088646)
		(layer "In6.Cu")
		(net "M_D_CPU0_SA_DQ<3>")
	)
	(segment
		(start 287.561782 -314.378848)
		(end 286.966152 -314.378848)
		(width 0.18288)
		(layer "In6.Cu")
		(net "M_D_CPU0_SA_DQ<3>")
	)
	(segment
		(start 269.4178 -314.355226)
		(end 268.829282 -313.766708)
		(width 0.18288)
		(layer "In6.Cu")
		(net "M_D_CPU0_SA_DQ<3>")
	)
	(segment
		(start 274.645882 -313.59729)
		(end 273.34718 -313.59729)
		(width 0.18288)
		(layer "In6.Cu")
		(net "M_D_CPU0_SA_DQ<3>")
	)
	(segment
		(start 316.633352 -296.68724)
		(end 316.633352 -298.64304)
		(width 0.18288)
		(layer "In6.Cu")
		(net "M_D_CPU0_SA_DQ<3>")
	)
	(segment
		(start 297.324018 -309.562754)
		(end 297.091354 -309.33009)
		(width 0.18288)
		(layer "In6.Cu")
		(net "M_D_CPU0_SA_DQ<3>")
	)
	(segment
		(start 314.683648 -300.592744)
		(end 313.58713 -300.592744)
		(width 0.18288)
		(layer "In6.Cu")
		(net "M_D_CPU0_SA_DQ<3>")
	)
	(segment
		(start 285.453582 -315.891418)
		(end 282.91282 -315.891418)
		(width 0.18288)
		(layer "In6.Cu")
		(net "M_D_CPU0_SA_DQ<3>")
	)
	(segment
		(start 278.849074 -314.40882)
		(end 277.523956 -314.40882)
		(width 0.18288)
		(layer "In6.Cu")
		(net "M_D_CPU0_SA_DQ<3>")
	)
	(segment
		(start 311.127648 -301.441612)
		(end 308.982364 -301.441612)
		(width 0.18288)
		(layer "In6.Cu")
		(net "M_D_CPU0_SA_DQ<3>")
	)
	(segment
		(start 333.57185 -280.283412)
		(end 333.56296 -280.288492)
		(width 0.088646)
		(layer "In6.Cu")
		(net "M_D_CPU0_SA_DQ<3>")
	)
	(segment
		(start 333.1718 -280.652474)
		(end 333.1718 -281.294332)
		(width 0.088646)
		(layer "In6.Cu")
		(net "M_D_CPU0_SA_DQ<3>")
	)
	(segment
		(start 332.987396 -281.478736)
		(end 332.50251 -281.478736)
		(width 0.088646)
		(layer "In6.Cu")
		(net "M_D_CPU0_SA_DQ<3>")
	)
	(segment
		(start 271.698974 -314.355226)
		(end 271.516094 -314.172346)
		(width 0.18288)
		(layer "In6.Cu")
		(net "M_D_CPU0_SA_DQ<3>")
	)
	(segment
		(start 342.702642 -276.049486)
		(end 342.670892 -276.08149)
		(width 0.088646)
		(layer "In6.Cu")
		(net "M_D_CPU0_SA_DQ<3>")
	)
	(segment
		(start 290.481004 -312.580528)
		(end 289.613086 -313.448446)
		(width 0.18288)
		(layer "In6.Cu")
		(net "M_D_CPU0_SA_DQ<3>")
	)
	(segment
		(start 275.336762 -312.902854)
		(end 275.011642 -312.902854)
		(width 0.18288)
		(layer "In6.Cu")
		(net "M_D_CPU0_SA_DQ<3>")
	)
	(segment
		(start 333.750412 -279.954228)
		(end 333.750412 -279.964134)
		(width 0.088646)
		(layer "In6.Cu")
		(net "M_D_CPU0_SA_DQ<3>")
	)
	(segment
		(start 334.04175 -279.469596)
		(end 334.03286 -279.474676)
		(width 0.088646)
		(layer "In6.Cu")
		(net "M_D_CPU0_SA_DQ<3>")
	)
	(segment
		(start 316.633352 -298.64304)
		(end 314.683648 -300.592744)
		(width 0.18288)
		(layer "In6.Cu")
		(net "M_D_CPU0_SA_DQ<3>")
	)
	(segment
		(start 292.845236 -311.935368)
		(end 292.038786 -311.935368)
		(width 0.18288)
		(layer "In6.Cu")
		(net "M_D_CPU0_SA_DQ<3>")
	)
	(segment
		(start 296.865294 -309.33009)
		(end 295.403524 -310.79186)
		(width 0.18288)
		(layer "In6.Cu")
		(net "M_D_CPU0_SA_DQ<3>")
	)
	(segment
		(start 306.072794 -304.169826)
		(end 304.32248 -305.92014)
		(width 0.18288)
		(layer "In6.Cu")
		(net "M_D_CPU0_SA_DQ<3>")
	)
	(segment
		(start 297.581828 -308.613556)
		(end 297.581828 -308.839616)
		(width 0.18288)
		(layer "In6.Cu")
		(net "M_D_CPU0_SA_DQ<3>")
	)
	(segment
		(start 343.436956 -275.573744)
		(end 343.425272 -275.56714)
		(width 0.088646)
		(layer "In6.Cu")
		(net "M_D_CPU0_SA_DQ<3>")
	)
	(segment
		(start 270.825214 -314.172346)
		(end 270.642334 -314.355226)
		(width 0.18288)
		(layer "In6.Cu")
		(net "M_D_CPU0_SA_DQ<3>")
	)
	(segment
		(start 337.33105 -278.65578)
		(end 337.32216 -278.66086)
		(width 0.088646)
		(layer "In6.Cu")
		(net "M_D_CPU0_SA_DQ<3>")
	)
	(segment
		(start 288.492184 -313.448446)
		(end 287.561782 -314.378848)
		(width 0.18288)
		(layer "In6.Cu")
		(net "M_D_CPU0_SA_DQ<3>")
	)
	(segment
		(start 270.642334 -314.355226)
		(end 269.4178 -314.355226)
		(width 0.18288)
		(layer "In6.Cu")
		(net "M_D_CPU0_SA_DQ<3>")
	)
	(segment
		(start 342.796622 -275.82241)
		(end 342.768174 -275.891244)
		(width 0.088646)
		(layer "In6.Cu")
		(net "M_D_CPU0_SA_DQ<3>")
	)
	(segment
		(start 331.841856 -281.478736)
		(end 316.633352 -296.68724)
		(width 0.18288)
		(layer "In6.Cu")
		(net "M_D_CPU0_SA_DQ<3>")
	)
	(segment
		(start 304.32248 -305.92014)
		(end 303.486566 -305.92014)
		(width 0.18288)
		(layer "In6.Cu")
		(net "M_D_CPU0_SA_DQ<3>")
	)
	(segment
		(start 302.01235 -306.737004)
		(end 300.507654 -308.2417)
		(width 0.18288)
		(layer "In6.Cu")
		(net "M_D_CPU0_SA_DQ<3>")
	)
	(segment
		(start 297.581828 -308.839616)
		(end 297.814492 -309.07228)
		(width 0.18288)
		(layer "In6.Cu")
		(net "M_D_CPU0_SA_DQ<3>")
	)
	(segment
		(start 273.34718 -313.59729)
		(end 272.589244 -314.355226)
		(width 0.18288)
		(layer "In6.Cu")
		(net "M_D_CPU0_SA_DQ<3>")
	)
	(segment
		(start 276.712426 -313.59729)
		(end 275.702522 -313.59729)
		(width 0.18288)
		(layer "In6.Cu")
		(net "M_D_CPU0_SA_DQ<3>")
	)
	(segment
		(start 332.50251 -281.478736)
		(end 331.841856 -281.478736)
		(width 0.18288)
		(layer "In6.Cu")
		(net "M_D_CPU0_SA_DQ<3>")
	)
	(segment
		(start 277.523956 -314.40882)
		(end 276.712426 -313.59729)
		(width 0.18288)
		(layer "In6.Cu")
		(net "M_D_CPU0_SA_DQ<3>")
	)
	(segment
		(start 274.828762 -313.085734)
		(end 274.828762 -313.41441)
		(width 0.18288)
		(layer "In6.Cu")
		(net "M_D_CPU0_SA_DQ<3>")
	)
	(segment
		(start 282.91282 -315.891418)
		(end 282.062936 -315.041534)
		(width 0.18288)
		(layer "In6.Cu")
		(net "M_D_CPU0_SA_DQ<3>")
	)
	(segment
		(start 307.227224 -303.196752)
		(end 307.227224 -303.581308)
		(width 0.18288)
		(layer "In6.Cu")
		(net "M_D_CPU0_SA_DQ<3>")
	)
	(segment
		(start 311.620916 -301.93488)
		(end 311.127648 -301.441612)
		(width 0.18288)
		(layer "In6.Cu")
		(net "M_D_CPU0_SA_DQ<3>")
	)
	(segment
		(start 275.702522 -313.59729)
		(end 275.519642 -313.41441)
		(width 0.18288)
		(layer "In6.Cu")
		(net "M_D_CPU0_SA_DQ<3>")
	)
	(segment
		(start 271.333214 -313.649614)
		(end 271.008094 -313.649614)
		(width 0.18288)
		(layer "In6.Cu")
		(net "M_D_CPU0_SA_DQ<3>")
	)
	(segment
		(start 313.58713 -300.592744)
		(end 312.244994 -301.93488)
		(width 0.18288)
		(layer "In6.Cu")
		(net "M_D_CPU0_SA_DQ<3>")
	)
	(segment
		(start 307.227224 -303.581308)
		(end 306.638706 -304.169826)
		(width 0.18288)
		(layer "In6.Cu")
		(net "M_D_CPU0_SA_DQ<3>")
	)
	(segment
		(start 340.237064 -276.219158)
		(end 340.222332 -276.210522)
		(width 0.088646)
		(layer "In6.Cu")
		(net "M_D_CPU0_SA_DQ<3>")
	)
	(segment
		(start 274.828762 -313.41441)
		(end 274.645882 -313.59729)
		(width 0.18288)
		(layer "In6.Cu")
		(net "M_D_CPU0_SA_DQ<3>")
	)
	(segment
		(start 271.516094 -313.832494)
		(end 271.333214 -313.649614)
		(width 0.18288)
		(layer "In6.Cu")
		(net "M_D_CPU0_SA_DQ<3>")
	)
	(segment
		(start 333.445866 -280.378408)
		(end 333.1718 -280.652474)
		(width 0.088646)
		(layer "In6.Cu")
		(net "M_D_CPU0_SA_DQ<3>")
	)
	(segment
		(start 297.814492 -309.07228)
		(end 297.814492 -309.29834)
		(width 0.18288)
		(layer "In6.Cu")
		(net "M_D_CPU0_SA_DQ<3>")
	)
	(arc
		(start 342.491314 -276.219158)
		(mid 342.304116 -276.269301)
		(end 342.116918 -276.219158)
		(width 0.088646)
		(layer "In6.Cu")
		(net "M_D_CPU0_SA_DQ<3>")
	)
	(arc
		(start 343.056464 -275.570442)
		(mid 342.958038 -275.636194)
		(end 342.869012 -275.714206)
		(width 0.088646)
		(layer "In6.Cu")
		(net "M_D_CPU0_SA_DQ<3>")
	)
	(arc
		(start 335.068164 -278.66086)
		(mid 334.785462 -278.585084)
		(end 334.50276 -278.66086)
		(width 0.088646)
		(layer "In6.Cu")
		(net "M_D_CPU0_SA_DQ<3>")
	)
	(arc
		(start 340.222332 -276.210522)
		(mid 339.945857 -276.143202)
		(end 339.67166 -276.219158)
		(width 0.088646)
		(layer "In6.Cu")
		(net "M_D_CPU0_SA_DQ<3>")
	)
	(arc
		(start 341.162132 -276.210522)
		(mid 340.885657 -276.143202)
		(end 340.61146 -276.219158)
		(width 0.088646)
		(layer "In6.Cu")
		(net "M_D_CPU0_SA_DQ<3>")
	)
	(arc
		(start 342.106504 -276.213062)
		(mid 341.828072 -276.143216)
		(end 341.55126 -276.219158)
		(width 0.088646)
		(layer "In6.Cu")
		(net "M_D_CPU0_SA_DQ<3>")
	)
	(arc
		(start 342.869012 -275.714206)
		(mid 342.827487 -275.764743)
		(end 342.796622 -275.82241)
		(width 0.088646)
		(layer "In6.Cu")
		(net "M_D_CPU0_SA_DQ<3>")
	)
	(arc
		(start 334.03286 -279.474676)
		(mid 333.828525 -279.677281)
		(end 333.750412 -279.954228)
		(width 0.088646)
		(layer "In6.Cu")
		(net "M_D_CPU0_SA_DQ<3>")
	)
	(arc
		(start 340.61146 -276.219158)
		(mid 340.424262 -276.269301)
		(end 340.237064 -276.219158)
		(width 0.088646)
		(layer "In6.Cu")
		(net "M_D_CPU0_SA_DQ<3>")
	)
	(arc
		(start 345.123262 -275.8948)
		(mid 344.950449 -275.87248)
		(end 344.788998 -275.806916)
		(width 0.088646)
		(layer "In6.Cu")
		(net "M_D_CPU0_SA_DQ<3>")
	)
	(arc
		(start 339.297264 -276.219158)
		(mid 339.014562 -276.143382)
		(end 338.73186 -276.219158)
		(width 0.088646)
		(layer "In6.Cu")
		(net "M_D_CPU0_SA_DQ<3>")
	)
	(arc
		(start 342.768174 -275.891244)
		(mid 342.75114 -275.976879)
		(end 342.702642 -276.049486)
		(width 0.088646)
		(layer "In6.Cu")
		(net "M_D_CPU0_SA_DQ<3>")
	)
	(arc
		(start 333.750412 -279.964134)
		(mid 333.702733 -280.147034)
		(end 333.57185 -280.283412)
		(width 0.088646)
		(layer "In6.Cu")
		(net "M_D_CPU0_SA_DQ<3>")
	)
	(arc
		(start 334.220312 -279.150318)
		(mid 334.172633 -279.333218)
		(end 334.04175 -279.469596)
		(width 0.088646)
		(layer "In6.Cu")
		(net "M_D_CPU0_SA_DQ<3>")
	)
	(arc
		(start 333.56296 -280.288492)
		(mid 333.501465 -280.329611)
		(end 333.445866 -280.378408)
		(width 0.088646)
		(layer "In6.Cu")
		(net "M_D_CPU0_SA_DQ<3>")
	)
	(arc
		(start 335.44256 -278.66086)
		(mid 335.255362 -278.711003)
		(end 335.068164 -278.66086)
		(width 0.088646)
		(layer "In6.Cu")
		(net "M_D_CPU0_SA_DQ<3>")
	)
	(arc
		(start 343.425272 -275.56714)
		(mid 343.240417 -275.52019)
		(end 343.056464 -275.570442)
		(width 0.088646)
		(layer "In6.Cu")
		(net "M_D_CPU0_SA_DQ<3>")
	)
	(arc
		(start 338.449412 -276.708616)
		(mid 338.401733 -276.891516)
		(end 338.27085 -277.027894)
		(width 0.088646)
		(layer "In6.Cu")
		(net "M_D_CPU0_SA_DQ<3>")
	)
	(arc
		(start 337.509612 -278.336502)
		(mid 337.461933 -278.519402)
		(end 337.33105 -278.65578)
		(width 0.088646)
		(layer "In6.Cu")
		(net "M_D_CPU0_SA_DQ<3>")
	)
	(arc
		(start 342.670892 -276.08149)
		(mid 342.585855 -276.156057)
		(end 342.491822 -276.218904)
		(width 0.088646)
		(layer "In6.Cu")
		(net "M_D_CPU0_SA_DQ<3>")
	)
	(arc
		(start 336.947764 -278.66086)
		(mid 336.665062 -278.585084)
		(end 336.38236 -278.66086)
		(width 0.088646)
		(layer "In6.Cu")
		(net "M_D_CPU0_SA_DQ<3>")
	)
	(arc
		(start 337.979512 -277.522432)
		(mid 337.931833 -277.705332)
		(end 337.80095 -277.84171)
		(width 0.088646)
		(layer "In6.Cu")
		(net "M_D_CPU0_SA_DQ<3>")
	)
	(arc
		(start 344.365072 -275.56714)
		(mid 344.180217 -275.52019)
		(end 343.996264 -275.570442)
		(width 0.088646)
		(layer "In6.Cu")
		(net "M_D_CPU0_SA_DQ<3>")
	)
	(arc
		(start 338.73186 -276.219158)
		(mid 338.527525 -276.421763)
		(end 338.449412 -276.69871)
		(width 0.088646)
		(layer "In6.Cu")
		(net "M_D_CPU0_SA_DQ<3>")
	)
	(arc
		(start 337.79206 -277.84679)
		(mid 337.589774 -278.045771)
		(end 337.509612 -278.31796)
		(width 0.088646)
		(layer "In6.Cu")
		(net "M_D_CPU0_SA_DQ<3>")
	)
	(arc
		(start 334.50276 -278.66086)
		(mid 334.298425 -278.863465)
		(end 334.220312 -279.140412)
		(width 0.088646)
		(layer "In6.Cu")
		(net "M_D_CPU0_SA_DQ<3>")
	)
	(arc
		(start 341.55126 -276.219158)
		(mid 341.364062 -276.269301)
		(end 341.176864 -276.219158)
		(width 0.088646)
		(layer "In6.Cu")
		(net "M_D_CPU0_SA_DQ<3>")
	)
	(arc
		(start 343.996264 -275.570442)
		(mid 343.717061 -275.646082)
		(end 343.436956 -275.573744)
		(width 0.088646)
		(layer "In6.Cu")
		(net "M_D_CPU0_SA_DQ<3>")
	)
	(arc
		(start 337.32216 -278.66086)
		(mid 337.134962 -278.711003)
		(end 336.947764 -278.66086)
		(width 0.088646)
		(layer "In6.Cu")
		(net "M_D_CPU0_SA_DQ<3>")
	)
	(arc
		(start 339.67166 -276.219158)
		(mid 339.484462 -276.269301)
		(end 339.297264 -276.219158)
		(width 0.088646)
		(layer "In6.Cu")
		(net "M_D_CPU0_SA_DQ<3>")
	)
	(arc
		(start 336.007964 -278.66086)
		(mid 335.725262 -278.585084)
		(end 335.44256 -278.66086)
		(width 0.088646)
		(layer "In6.Cu")
		(net "M_D_CPU0_SA_DQ<3>")
	)
	(arc
		(start 338.255864 -277.03653)
		(mid 338.053451 -277.242943)
		(end 337.979512 -277.522432)
		(width 0.088646)
		(layer "In6.Cu")
		(net "M_D_CPU0_SA_DQ<3>")
	)
	(arc
		(start 336.38236 -278.66086)
		(mid 336.195162 -278.711003)
		(end 336.007964 -278.66086)
		(width 0.088646)
		(layer "In6.Cu")
		(net "M_D_CPU0_SA_DQ<3>")
	)
	(segment
		(start 265.518646 -279.890982)
		(end 265.518646 -280.04262)
		(width 0.20066)
		(layer "F.Cu")
		(net "M_D_CPU0_SA_DQ<31>")
	)
	(segment
		(start 262.003794 -280.063448)
		(end 262.003794 -279.89276)
		(width 0.20066)
		(layer "F.Cu")
		(net "M_D_CPU0_SA_DQ<31>")
	)
	(segment
		(start 347.942916 -265.592306)
		(end 347.942662 -265.592306)
		(width 0.20066)
		(layer "F.Cu")
		(net "M_D_CPU0_SA_DQ<31>")
	)
	(segment
		(start 266.90828 -279.766776)
		(end 266.700762 -279.974294)
		(width 0.20066)
		(layer "F.Cu")
		(net "M_D_CPU0_SA_DQ<31>")
	)
	(segment
		(start 267.724382 -279.766776)
		(end 266.90828 -279.766776)
		(width 0.20066)
		(layer "F.Cu")
		(net "M_D_CPU0_SA_DQ<31>")
	)
	(segment
		(start 264.825226 -280.191718)
		(end 262.752332 -280.191718)
		(width 0.1016)
		(layer "F.Cu")
		(net "M_D_CPU0_SA_DQ<31>")
	)
	(segment
		(start 265.518646 -280.04262)
		(end 265.369548 -280.191718)
		(width 0.20066)
		(layer "F.Cu")
		(net "M_D_CPU0_SA_DQ<31>")
	)
	(segment
		(start 262.003794 -279.89276)
		(end 261.87781 -279.766776)
		(width 0.20066)
		(layer "F.Cu")
		(net "M_D_CPU0_SA_DQ<31>")
	)
	(segment
		(start 261.87781 -279.766776)
		(end 260.180582 -279.766776)
		(width 0.20066)
		(layer "F.Cu")
		(net "M_D_CPU0_SA_DQ<31>")
	)
	(segment
		(start 266.042394 -279.762458)
		(end 265.64717 -279.762458)
		(width 0.20066)
		(layer "F.Cu")
		(net "M_D_CPU0_SA_DQ<31>")
	)
	(segment
		(start 262.50011 -280.205942)
		(end 262.146288 -280.205942)
		(width 0.20066)
		(layer "F.Cu")
		(net "M_D_CPU0_SA_DQ<31>")
	)
	(segment
		(start 262.752332 -280.191718)
		(end 262.514334 -280.191718)
		(width 0.101854)
		(layer "F.Cu")
		(net "M_D_CPU0_SA_DQ<31>")
	)
	(segment
		(start 265.64717 -279.762458)
		(end 265.518646 -279.890982)
		(width 0.20066)
		(layer "F.Cu")
		(net "M_D_CPU0_SA_DQ<31>")
	)
	(segment
		(start 266.25423 -279.974294)
		(end 266.042394 -279.762458)
		(width 0.20066)
		(layer "F.Cu")
		(net "M_D_CPU0_SA_DQ<31>")
	)
	(segment
		(start 265.369548 -280.191718)
		(end 264.825226 -280.191718)
		(width 0.20066)
		(layer "F.Cu")
		(net "M_D_CPU0_SA_DQ<31>")
	)
	(segment
		(start 262.514334 -280.191718)
		(end 262.50011 -280.205942)
		(width 0.101854)
		(layer "F.Cu")
		(net "M_D_CPU0_SA_DQ<31>")
	)
	(segment
		(start 268.829282 -279.766776)
		(end 267.724382 -279.766776)
		(width 0.20066)
		(layer "F.Cu")
		(net "M_D_CPU0_SA_DQ<31>")
	)
	(segment
		(start 262.146288 -280.205942)
		(end 262.003794 -280.063448)
		(width 0.20066)
		(layer "F.Cu")
		(net "M_D_CPU0_SA_DQ<31>")
	)
	(segment
		(start 266.700762 -279.974294)
		(end 266.25423 -279.974294)
		(width 0.20066)
		(layer "F.Cu")
		(net "M_D_CPU0_SA_DQ<31>")
	)
	(segment
		(start 347.942662 -265.592306)
		(end 347.942662 -266.128246)
		(width 0.20066)
		(layer "F.Cu")
		(net "M_D_CPU0_SA_DQ<31>")
	)
	(segment
		(start 271.496028 -279.97658)
		(end 271.302988 -279.78354)
		(width 0.18288)
		(layer "In11.Cu")
		(net "M_D_CPU0_SA_DQ<31>")
	)
	(segment
		(start 343.915746 -265.629898)
		(end 343.901014 -265.638534)
		(width 0.088646)
		(layer "In11.Cu")
		(net "M_D_CPU0_SA_DQ<31>")
	)
	(segment
		(start 307.765958 -277.013162)
		(end 306.949094 -277.830026)
		(width 0.18288)
		(layer "In11.Cu")
		(net "M_D_CPU0_SA_DQ<31>")
	)
	(segment
		(start 288.89325 -278.473662)
		(end 288.70021 -278.280622)
		(width 0.18288)
		(layer "In11.Cu")
		(net "M_D_CPU0_SA_DQ<31>")
	)
	(segment
		(start 276.875494 -279.455626)
		(end 275.909278 -279.455626)
		(width 0.18288)
		(layer "In11.Cu")
		(net "M_D_CPU0_SA_DQ<31>")
	)
	(segment
		(start 277.875238 -279.266396)
		(end 277.606506 -278.997664)
		(width 0.18288)
		(layer "In11.Cu")
		(net "M_D_CPU0_SA_DQ<31>")
	)
	(segment
		(start 299.288454 -278.492712)
		(end 299.061886 -278.492712)
		(width 0.18288)
		(layer "In11.Cu")
		(net "M_D_CPU0_SA_DQ<31>")
	)
	(segment
		(start 288.70021 -277.816818)
		(end 288.50717 -277.623778)
		(width 0.18288)
		(layer "In11.Cu")
		(net "M_D_CPU0_SA_DQ<31>")
	)
	(segment
		(start 284.594046 -278.491442)
		(end 283.319728 -278.491442)
		(width 0.18288)
		(layer "In11.Cu")
		(net "M_D_CPU0_SA_DQ<31>")
	)
	(segment
		(start 289.59429 -277.623778)
		(end 289.40125 -277.816818)
		(width 0.18288)
		(layer "In11.Cu")
		(net "M_D_CPU0_SA_DQ<31>")
	)
	(segment
		(start 291.20973 -279.432004)
		(end 290.10229 -278.324564)
		(width 0.18288)
		(layer "In11.Cu")
		(net "M_D_CPU0_SA_DQ<31>")
	)
	(segment
		(start 278.480266 -278.887428)
		(end 278.261572 -279.106122)
		(width 0.18288)
		(layer "In11.Cu")
		(net "M_D_CPU0_SA_DQ<31>")
	)
	(segment
		(start 278.261572 -279.106122)
		(end 278.261572 -279.106376)
		(width 0.18288)
		(layer "In11.Cu")
		(net "M_D_CPU0_SA_DQ<31>")
	)
	(segment
		(start 315.21781 -276.227286)
		(end 311.469024 -276.227286)
		(width 0.18288)
		(layer "In11.Cu")
		(net "M_D_CPU0_SA_DQ<31>")
	)
	(segment
		(start 331.068426 -266.733274)
		(end 330.903072 -266.733274)
		(width 0.088646)
		(layer "In11.Cu")
		(net "M_D_CPU0_SA_DQ<31>")
	)
	(segment
		(start 292.330378 -278.820118)
		(end 291.718492 -279.432004)
		(width 0.18288)
		(layer "In11.Cu")
		(net "M_D_CPU0_SA_DQ<31>")
	)
	(segment
		(start 342.036146 -265.629898)
		(end 342.021414 -265.638534)
		(width 0.088646)
		(layer "In11.Cu")
		(net "M_D_CPU0_SA_DQ<31>")
	)
	(segment
		(start 289.40125 -277.816818)
		(end 289.40125 -278.280622)
		(width 0.18288)
		(layer "In11.Cu")
		(net "M_D_CPU0_SA_DQ<31>")
	)
	(segment
		(start 341.096346 -265.629898)
		(end 341.081614 -265.638534)
		(width 0.088646)
		(layer "In11.Cu")
		(net "M_D_CPU0_SA_DQ<31>")
	)
	(segment
		(start 301.393606 -277.901146)
		(end 301.200566 -278.094186)
		(width 0.18288)
		(layer "In11.Cu")
		(net "M_D_CPU0_SA_DQ<31>")
	)
	(segment
		(start 278.101552 -279.266396)
		(end 277.875238 -279.266396)
		(width 0.18288)
		(layer "In11.Cu")
		(net "M_D_CPU0_SA_DQ<31>")
	)
	(segment
		(start 287.80613 -278.517604)
		(end 286.827722 -278.517604)
		(width 0.18288)
		(layer "In11.Cu")
		(net "M_D_CPU0_SA_DQ<31>")
	)
	(segment
		(start 324.711822 -266.733274)
		(end 315.21781 -276.227286)
		(width 0.18288)
		(layer "In11.Cu")
		(net "M_D_CPU0_SA_DQ<31>")
	)
	(segment
		(start 301.007526 -278.605996)
		(end 299.401738 -278.605996)
		(width 0.18288)
		(layer "In11.Cu")
		(net "M_D_CPU0_SA_DQ<31>")
	)
	(segment
		(start 299.401738 -278.605996)
		(end 299.288454 -278.492712)
		(width 0.18288)
		(layer "In11.Cu")
		(net "M_D_CPU0_SA_DQ<31>")
	)
	(segment
		(start 291.718492 -279.432004)
		(end 291.20973 -279.432004)
		(width 0.18288)
		(layer "In11.Cu")
		(net "M_D_CPU0_SA_DQ<31>")
	)
	(segment
		(start 332.435962 -265.689334)
		(end 331.872082 -265.689334)
		(width 0.088646)
		(layer "In11.Cu")
		(net "M_D_CPU0_SA_DQ<31>")
	)
	(segment
		(start 286.441642 -278.013922)
		(end 286.126682 -278.013922)
		(width 0.18288)
		(layer "In11.Cu")
		(net "M_D_CPU0_SA_DQ<31>")
	)
	(segment
		(start 301.708566 -277.901146)
		(end 301.393606 -277.901146)
		(width 0.18288)
		(layer "In11.Cu")
		(net "M_D_CPU0_SA_DQ<31>")
	)
	(segment
		(start 290.10229 -278.324564)
		(end 290.10229 -277.816818)
		(width 0.18288)
		(layer "In11.Cu")
		(net "M_D_CPU0_SA_DQ<31>")
	)
	(segment
		(start 271.496028 -280.075386)
		(end 271.496028 -279.97658)
		(width 0.18288)
		(layer "In11.Cu")
		(net "M_D_CPU0_SA_DQ<31>")
	)
	(segment
		(start 287.99917 -278.324564)
		(end 287.80613 -278.517604)
		(width 0.18288)
		(layer "In11.Cu")
		(net "M_D_CPU0_SA_DQ<31>")
	)
	(segment
		(start 286.634682 -278.206962)
		(end 286.441642 -278.013922)
		(width 0.18288)
		(layer "In11.Cu")
		(net "M_D_CPU0_SA_DQ<31>")
	)
	(segment
		(start 339.212428 -265.632438)
		(end 339.202014 -265.638534)
		(width 0.088646)
		(layer "In11.Cu")
		(net "M_D_CPU0_SA_DQ<31>")
	)
	(segment
		(start 273.751294 -279.455626)
		(end 272.938494 -280.268426)
		(width 0.18288)
		(layer "In11.Cu")
		(net "M_D_CPU0_SA_DQ<31>")
	)
	(segment
		(start 286.827722 -278.517604)
		(end 286.634682 -278.324564)
		(width 0.18288)
		(layer "In11.Cu")
		(net "M_D_CPU0_SA_DQ<31>")
	)
	(segment
		(start 288.50717 -277.623778)
		(end 288.19221 -277.623778)
		(width 0.18288)
		(layer "In11.Cu")
		(net "M_D_CPU0_SA_DQ<31>")
	)
	(segment
		(start 285.933642 -278.206962)
		(end 285.933642 -278.324564)
		(width 0.18288)
		(layer "In11.Cu")
		(net "M_D_CPU0_SA_DQ<31>")
	)
	(segment
		(start 346.730574 -265.632438)
		(end 346.72016 -265.638534)
		(width 0.088646)
		(layer "In11.Cu")
		(net "M_D_CPU0_SA_DQ<31>")
	)
	(segment
		(start 301.901606 -278.412956)
		(end 301.901606 -278.094186)
		(width 0.18288)
		(layer "In11.Cu")
		(net "M_D_CPU0_SA_DQ<31>")
	)
	(segment
		(start 302.094646 -278.605996)
		(end 301.901606 -278.412956)
		(width 0.18288)
		(layer "In11.Cu")
		(net "M_D_CPU0_SA_DQ<31>")
	)
	(segment
		(start 278.753316 -278.887428)
		(end 278.480266 -278.887428)
		(width 0.18288)
		(layer "In11.Cu")
		(net "M_D_CPU0_SA_DQ<31>")
	)
	(segment
		(start 286.126682 -278.013922)
		(end 285.933642 -278.206962)
		(width 0.18288)
		(layer "In11.Cu")
		(net "M_D_CPU0_SA_DQ<31>")
	)
	(segment
		(start 347.942662 -266.128246)
		(end 347.942408 -266.127992)
		(width 0.088646)
		(layer "In11.Cu")
		(net "M_D_CPU0_SA_DQ<31>")
	)
	(segment
		(start 338.272374 -265.632438)
		(end 338.26196 -265.638534)
		(width 0.088646)
		(layer "In11.Cu")
		(net "M_D_CPU0_SA_DQ<31>")
	)
	(segment
		(start 311.469024 -276.227286)
		(end 310.683148 -277.013162)
		(width 0.18288)
		(layer "In11.Cu")
		(net "M_D_CPU0_SA_DQ<31>")
	)
	(segment
		(start 289.40125 -278.280622)
		(end 289.20821 -278.473662)
		(width 0.18288)
		(layer "In11.Cu")
		(net "M_D_CPU0_SA_DQ<31>")
	)
	(segment
		(start 274.822158 -279.455626)
		(end 273.751294 -279.455626)
		(width 0.18288)
		(layer "In11.Cu")
		(net "M_D_CPU0_SA_DQ<31>")
	)
	(segment
		(start 284.777434 -278.67483)
		(end 284.594046 -278.491442)
		(width 0.18288)
		(layer "In11.Cu")
		(net "M_D_CPU0_SA_DQ<31>")
	)
	(segment
		(start 301.200566 -278.412956)
		(end 301.007526 -278.605996)
		(width 0.18288)
		(layer "In11.Cu")
		(net "M_D_CPU0_SA_DQ<31>")
	)
	(segment
		(start 345.791028 -265.632438)
		(end 345.780614 -265.638534)
		(width 0.088646)
		(layer "In11.Cu")
		(net "M_D_CPU0_SA_DQ<31>")
	)
	(segment
		(start 342.975946 -265.629898)
		(end 342.961214 -265.638534)
		(width 0.088646)
		(layer "In11.Cu")
		(net "M_D_CPU0_SA_DQ<31>")
	)
	(segment
		(start 293.40175 -279.344882)
		(end 292.876986 -278.820118)
		(width 0.18288)
		(layer "In11.Cu")
		(net "M_D_CPU0_SA_DQ<31>")
	)
	(segment
		(start 285.583376 -278.67483)
		(end 284.777434 -278.67483)
		(width 0.18288)
		(layer "In11.Cu")
		(net "M_D_CPU0_SA_DQ<31>")
	)
	(segment
		(start 290.10229 -277.816818)
		(end 289.90925 -277.623778)
		(width 0.18288)
		(layer "In11.Cu")
		(net "M_D_CPU0_SA_DQ<31>")
	)
	(segment
		(start 275.909278 -279.455626)
		(end 275.716238 -279.262586)
		(width 0.18288)
		(layer "In11.Cu")
		(net "M_D_CPU0_SA_DQ<31>")
	)
	(segment
		(start 270.794988 -279.97658)
		(end 270.794988 -280.075386)
		(width 0.18288)
		(layer "In11.Cu")
		(net "M_D_CPU0_SA_DQ<31>")
	)
	(segment
		(start 330.903072 -266.733274)
		(end 324.711822 -266.733274)
		(width 0.18288)
		(layer "In11.Cu")
		(net "M_D_CPU0_SA_DQ<31>")
	)
	(segment
		(start 288.19221 -277.623778)
		(end 287.99917 -277.816818)
		(width 0.18288)
		(layer "In11.Cu")
		(net "M_D_CPU0_SA_DQ<31>")
	)
	(segment
		(start 275.015198 -279.262586)
		(end 274.822158 -279.455626)
		(width 0.18288)
		(layer "In11.Cu")
		(net "M_D_CPU0_SA_DQ<31>")
	)
	(segment
		(start 277.333456 -278.997664)
		(end 276.875494 -279.455626)
		(width 0.18288)
		(layer "In11.Cu")
		(net "M_D_CPU0_SA_DQ<31>")
	)
	(segment
		(start 289.90925 -277.623778)
		(end 289.59429 -277.623778)
		(width 0.18288)
		(layer "In11.Cu")
		(net "M_D_CPU0_SA_DQ<31>")
	)
	(segment
		(start 275.716238 -279.065736)
		(end 275.523198 -278.872696)
		(width 0.18288)
		(layer "In11.Cu")
		(net "M_D_CPU0_SA_DQ<31>")
	)
	(segment
		(start 275.716238 -279.262586)
		(end 275.716238 -279.065736)
		(width 0.18288)
		(layer "In11.Cu")
		(net "M_D_CPU0_SA_DQ<31>")
	)
	(segment
		(start 298.934886 -278.491188)
		(end 298.933362 -278.492712)
		(width 0.18288)
		(layer "In11.Cu")
		(net "M_D_CPU0_SA_DQ<31>")
	)
	(segment
		(start 306.949094 -277.830026)
		(end 303.709578 -277.830026)
		(width 0.18288)
		(layer "In11.Cu")
		(net "M_D_CPU0_SA_DQ<31>")
	)
	(segment
		(start 271.302988 -279.78354)
		(end 270.988028 -279.78354)
		(width 0.18288)
		(layer "In11.Cu")
		(net "M_D_CPU0_SA_DQ<31>")
	)
	(segment
		(start 270.601948 -280.268426)
		(end 269.330932 -280.268426)
		(width 0.18288)
		(layer "In11.Cu")
		(net "M_D_CPU0_SA_DQ<31>")
	)
	(segment
		(start 340.151974 -265.632438)
		(end 340.14156 -265.638534)
		(width 0.088646)
		(layer "In11.Cu")
		(net "M_D_CPU0_SA_DQ<31>")
	)
	(segment
		(start 272.938494 -280.268426)
		(end 271.689068 -280.268426)
		(width 0.18288)
		(layer "In11.Cu")
		(net "M_D_CPU0_SA_DQ<31>")
	)
	(segment
		(start 277.606506 -278.997664)
		(end 277.333456 -278.997664)
		(width 0.18288)
		(layer "In11.Cu")
		(net "M_D_CPU0_SA_DQ<31>")
	)
	(segment
		(start 271.689068 -280.268426)
		(end 271.496028 -280.075386)
		(width 0.18288)
		(layer "In11.Cu")
		(net "M_D_CPU0_SA_DQ<31>")
	)
	(segment
		(start 303.709578 -277.830026)
		(end 302.933608 -278.605996)
		(width 0.18288)
		(layer "In11.Cu")
		(net "M_D_CPU0_SA_DQ<31>")
	)
	(segment
		(start 283.319728 -278.491442)
		(end 282.466288 -279.344882)
		(width 0.18288)
		(layer "In11.Cu")
		(net "M_D_CPU0_SA_DQ<31>")
	)
	(segment
		(start 275.208238 -278.872696)
		(end 275.015198 -279.065736)
		(width 0.18288)
		(layer "In11.Cu")
		(net "M_D_CPU0_SA_DQ<31>")
	)
	(segment
		(start 286.634682 -278.324564)
		(end 286.634682 -278.206962)
		(width 0.18288)
		(layer "In11.Cu")
		(net "M_D_CPU0_SA_DQ<31>")
	)
	(segment
		(start 344.855546 -265.629898)
		(end 344.840814 -265.638534)
		(width 0.088646)
		(layer "In11.Cu")
		(net "M_D_CPU0_SA_DQ<31>")
	)
	(segment
		(start 347.629988 -266.127992)
		(end 347.564456 -266.06246)
		(width 0.088646)
		(layer "In11.Cu")
		(net "M_D_CPU0_SA_DQ<31>")
	)
	(segment
		(start 331.157072 -266.644628)
		(end 331.068426 -266.733274)
		(width 0.088646)
		(layer "In11.Cu")
		(net "M_D_CPU0_SA_DQ<31>")
	)
	(segment
		(start 299.060362 -278.491188)
		(end 298.934886 -278.491188)
		(width 0.18288)
		(layer "In11.Cu")
		(net "M_D_CPU0_SA_DQ<31>")
	)
	(segment
		(start 289.20821 -278.473662)
		(end 288.89325 -278.473662)
		(width 0.18288)
		(layer "In11.Cu")
		(net "M_D_CPU0_SA_DQ<31>")
	)
	(segment
		(start 282.466288 -279.344882)
		(end 279.21077 -279.344882)
		(width 0.18288)
		(layer "In11.Cu")
		(net "M_D_CPU0_SA_DQ<31>")
	)
	(segment
		(start 301.200566 -278.094186)
		(end 301.200566 -278.412956)
		(width 0.18288)
		(layer "In11.Cu")
		(net "M_D_CPU0_SA_DQ<31>")
	)
	(segment
		(start 299.061886 -278.492712)
		(end 299.060362 -278.491188)
		(width 0.18288)
		(layer "In11.Cu")
		(net "M_D_CPU0_SA_DQ<31>")
	)
	(segment
		(start 285.933642 -278.324564)
		(end 285.583376 -278.67483)
		(width 0.18288)
		(layer "In11.Cu")
		(net "M_D_CPU0_SA_DQ<31>")
	)
	(segment
		(start 278.261572 -279.106376)
		(end 278.101552 -279.266396)
		(width 0.18288)
		(layer "In11.Cu")
		(net "M_D_CPU0_SA_DQ<31>")
	)
	(segment
		(start 270.794988 -280.075386)
		(end 270.601948 -280.268426)
		(width 0.18288)
		(layer "In11.Cu")
		(net "M_D_CPU0_SA_DQ<31>")
	)
	(segment
		(start 297.103038 -279.344882)
		(end 293.40175 -279.344882)
		(width 0.18288)
		(layer "In11.Cu")
		(net "M_D_CPU0_SA_DQ<31>")
	)
	(segment
		(start 310.683148 -277.013162)
		(end 307.765958 -277.013162)
		(width 0.18288)
		(layer "In11.Cu")
		(net "M_D_CPU0_SA_DQ<31>")
	)
	(segment
		(start 288.70021 -278.280622)
		(end 288.70021 -277.816818)
		(width 0.18288)
		(layer "In11.Cu")
		(net "M_D_CPU0_SA_DQ<31>")
	)
	(segment
		(start 292.876986 -278.820118)
		(end 292.330378 -278.820118)
		(width 0.18288)
		(layer "In11.Cu")
		(net "M_D_CPU0_SA_DQ<31>")
	)
	(segment
		(start 275.523198 -278.872696)
		(end 275.208238 -278.872696)
		(width 0.18288)
		(layer "In11.Cu")
		(net "M_D_CPU0_SA_DQ<31>")
	)
	(segment
		(start 270.988028 -279.78354)
		(end 270.794988 -279.97658)
		(width 0.18288)
		(layer "In11.Cu")
		(net "M_D_CPU0_SA_DQ<31>")
	)
	(segment
		(start 275.015198 -279.065736)
		(end 275.015198 -279.262586)
		(width 0.18288)
		(layer "In11.Cu")
		(net "M_D_CPU0_SA_DQ<31>")
	)
	(segment
		(start 287.99917 -277.816818)
		(end 287.99917 -278.324564)
		(width 0.18288)
		(layer "In11.Cu")
		(net "M_D_CPU0_SA_DQ<31>")
	)
	(segment
		(start 279.21077 -279.344882)
		(end 278.753316 -278.887428)
		(width 0.18288)
		(layer "In11.Cu")
		(net "M_D_CPU0_SA_DQ<31>")
	)
	(segment
		(start 297.955208 -278.492712)
		(end 297.103038 -279.344882)
		(width 0.18288)
		(layer "In11.Cu")
		(net "M_D_CPU0_SA_DQ<31>")
	)
	(segment
		(start 302.933608 -278.605996)
		(end 302.094646 -278.605996)
		(width 0.18288)
		(layer "In11.Cu")
		(net "M_D_CPU0_SA_DQ<31>")
	)
	(segment
		(start 331.872082 -265.689334)
		(end 331.157072 -266.404344)
		(width 0.088646)
		(layer "In11.Cu")
		(net "M_D_CPU0_SA_DQ<31>")
	)
	(segment
		(start 331.157072 -266.404344)
		(end 331.157072 -266.644628)
		(width 0.088646)
		(layer "In11.Cu")
		(net "M_D_CPU0_SA_DQ<31>")
	)
	(segment
		(start 347.942408 -266.127992)
		(end 347.629988 -266.127992)
		(width 0.088646)
		(layer "In11.Cu")
		(net "M_D_CPU0_SA_DQ<31>")
	)
	(segment
		(start 269.330932 -280.268426)
		(end 268.829282 -279.766776)
		(width 0.18288)
		(layer "In11.Cu")
		(net "M_D_CPU0_SA_DQ<31>")
	)
	(segment
		(start 301.901606 -278.094186)
		(end 301.708566 -277.901146)
		(width 0.18288)
		(layer "In11.Cu")
		(net "M_D_CPU0_SA_DQ<31>")
	)
	(segment
		(start 298.933362 -278.492712)
		(end 297.955208 -278.492712)
		(width 0.18288)
		(layer "In11.Cu")
		(net "M_D_CPU0_SA_DQ<31>")
	)
	(arc
		(start 336.947764 -265.638534)
		(mid 336.665062 -265.562758)
		(end 336.38236 -265.638534)
		(width 0.088646)
		(layer "In11.Cu")
		(net "M_D_CPU0_SA_DQ<31>")
	)
	(arc
		(start 338.827618 -265.638534)
		(mid 338.550805 -265.562664)
		(end 338.272374 -265.632438)
		(width 0.088646)
		(layer "In11.Cu")
		(net "M_D_CPU0_SA_DQ<31>")
	)
	(arc
		(start 333.188564 -265.638534)
		(mid 332.905862 -265.562792)
		(end 332.62316 -265.638534)
		(width 0.088646)
		(layer "In11.Cu")
		(net "M_D_CPU0_SA_DQ<31>")
	)
	(arc
		(start 336.38236 -265.638534)
		(mid 336.195162 -265.688677)
		(end 336.007964 -265.638534)
		(width 0.088646)
		(layer "In11.Cu")
		(net "M_D_CPU0_SA_DQ<31>")
	)
	(arc
		(start 334.128364 -265.638534)
		(mid 333.845662 -265.562792)
		(end 333.56296 -265.638534)
		(width 0.088646)
		(layer "In11.Cu")
		(net "M_D_CPU0_SA_DQ<31>")
	)
	(arc
		(start 333.56296 -265.638534)
		(mid 333.375762 -265.688677)
		(end 333.188564 -265.638534)
		(width 0.088646)
		(layer "In11.Cu")
		(net "M_D_CPU0_SA_DQ<31>")
	)
	(arc
		(start 343.526618 -265.638534)
		(mid 343.252419 -265.562699)
		(end 342.975946 -265.629898)
		(width 0.088646)
		(layer "In11.Cu")
		(net "M_D_CPU0_SA_DQ<31>")
	)
	(arc
		(start 344.466418 -265.638534)
		(mid 344.192219 -265.562699)
		(end 343.915746 -265.629898)
		(width 0.088646)
		(layer "In11.Cu")
		(net "M_D_CPU0_SA_DQ<31>")
	)
	(arc
		(start 337.32216 -265.638534)
		(mid 337.134962 -265.688677)
		(end 336.947764 -265.638534)
		(width 0.088646)
		(layer "In11.Cu")
		(net "M_D_CPU0_SA_DQ<31>")
	)
	(arc
		(start 343.901014 -265.638534)
		(mid 343.713816 -265.688677)
		(end 343.526618 -265.638534)
		(width 0.088646)
		(layer "In11.Cu")
		(net "M_D_CPU0_SA_DQ<31>")
	)
	(arc
		(start 339.202014 -265.638534)
		(mid 339.014816 -265.688677)
		(end 338.827618 -265.638534)
		(width 0.088646)
		(layer "In11.Cu")
		(net "M_D_CPU0_SA_DQ<31>")
	)
	(arc
		(start 335.068164 -265.638534)
		(mid 334.785462 -265.562792)
		(end 334.50276 -265.638534)
		(width 0.088646)
		(layer "In11.Cu")
		(net "M_D_CPU0_SA_DQ<31>")
	)
	(arc
		(start 344.840814 -265.638534)
		(mid 344.653616 -265.688677)
		(end 344.466418 -265.638534)
		(width 0.088646)
		(layer "In11.Cu")
		(net "M_D_CPU0_SA_DQ<31>")
	)
	(arc
		(start 347.564456 -266.06246)
		(mid 347.475368 -265.817475)
		(end 347.285818 -265.638534)
		(width 0.088646)
		(layer "In11.Cu")
		(net "M_D_CPU0_SA_DQ<31>")
	)
	(arc
		(start 341.647018 -265.638534)
		(mid 341.372819 -265.562699)
		(end 341.096346 -265.629898)
		(width 0.088646)
		(layer "In11.Cu")
		(net "M_D_CPU0_SA_DQ<31>")
	)
	(arc
		(start 336.007964 -265.638534)
		(mid 335.725262 -265.562792)
		(end 335.44256 -265.638534)
		(width 0.088646)
		(layer "In11.Cu")
		(net "M_D_CPU0_SA_DQ<31>")
	)
	(arc
		(start 340.14156 -265.638534)
		(mid 339.954362 -265.688677)
		(end 339.767164 -265.638534)
		(width 0.088646)
		(layer "In11.Cu")
		(net "M_D_CPU0_SA_DQ<31>")
	)
	(arc
		(start 342.021414 -265.638534)
		(mid 341.834216 -265.688677)
		(end 341.647018 -265.638534)
		(width 0.088646)
		(layer "In11.Cu")
		(net "M_D_CPU0_SA_DQ<31>")
	)
	(arc
		(start 334.50276 -265.638534)
		(mid 334.315562 -265.688677)
		(end 334.128364 -265.638534)
		(width 0.088646)
		(layer "In11.Cu")
		(net "M_D_CPU0_SA_DQ<31>")
	)
	(arc
		(start 346.345764 -265.638534)
		(mid 346.069205 -265.562791)
		(end 345.791028 -265.632438)
		(width 0.088646)
		(layer "In11.Cu")
		(net "M_D_CPU0_SA_DQ<31>")
	)
	(arc
		(start 342.961214 -265.638534)
		(mid 342.774016 -265.688677)
		(end 342.586818 -265.638534)
		(width 0.088646)
		(layer "In11.Cu")
		(net "M_D_CPU0_SA_DQ<31>")
	)
	(arc
		(start 345.406218 -265.638534)
		(mid 345.132019 -265.562699)
		(end 344.855546 -265.629898)
		(width 0.088646)
		(layer "In11.Cu")
		(net "M_D_CPU0_SA_DQ<31>")
	)
	(arc
		(start 337.887564 -265.638534)
		(mid 337.604862 -265.562758)
		(end 337.32216 -265.638534)
		(width 0.088646)
		(layer "In11.Cu")
		(net "M_D_CPU0_SA_DQ<31>")
	)
	(arc
		(start 332.62316 -265.638534)
		(mid 332.532904 -265.676256)
		(end 332.435962 -265.689334)
		(width 0.088646)
		(layer "In11.Cu")
		(net "M_D_CPU0_SA_DQ<31>")
	)
	(arc
		(start 339.767164 -265.638534)
		(mid 339.490605 -265.562791)
		(end 339.212428 -265.632438)
		(width 0.088646)
		(layer "In11.Cu")
		(net "M_D_CPU0_SA_DQ<31>")
	)
	(arc
		(start 346.72016 -265.638534)
		(mid 346.532962 -265.688677)
		(end 346.345764 -265.638534)
		(width 0.088646)
		(layer "In11.Cu")
		(net "M_D_CPU0_SA_DQ<31>")
	)
	(arc
		(start 335.44256 -265.638534)
		(mid 335.255362 -265.688677)
		(end 335.068164 -265.638534)
		(width 0.088646)
		(layer "In11.Cu")
		(net "M_D_CPU0_SA_DQ<31>")
	)
	(arc
		(start 347.285818 -265.638534)
		(mid 347.009005 -265.562664)
		(end 346.730574 -265.632438)
		(width 0.088646)
		(layer "In11.Cu")
		(net "M_D_CPU0_SA_DQ<31>")
	)
	(arc
		(start 338.26196 -265.638534)
		(mid 338.074762 -265.688677)
		(end 337.887564 -265.638534)
		(width 0.088646)
		(layer "In11.Cu")
		(net "M_D_CPU0_SA_DQ<31>")
	)
	(arc
		(start 342.586818 -265.638534)
		(mid 342.312619 -265.562699)
		(end 342.036146 -265.629898)
		(width 0.088646)
		(layer "In11.Cu")
		(net "M_D_CPU0_SA_DQ<31>")
	)
	(arc
		(start 340.707218 -265.638534)
		(mid 340.430405 -265.562664)
		(end 340.151974 -265.632438)
		(width 0.088646)
		(layer "In11.Cu")
		(net "M_D_CPU0_SA_DQ<31>")
	)
	(arc
		(start 341.081614 -265.638534)
		(mid 340.894416 -265.688677)
		(end 340.707218 -265.638534)
		(width 0.088646)
		(layer "In11.Cu")
		(net "M_D_CPU0_SA_DQ<31>")
	)
	(arc
		(start 345.780614 -265.638534)
		(mid 345.593416 -265.688677)
		(end 345.406218 -265.638534)
		(width 0.088646)
		(layer "In11.Cu")
		(net "M_D_CPU0_SA_DQ<31>")
	)
	(segment
		(start 265.458194 -281.041856)
		(end 264.825226 -281.041856)
		(width 0.20066)
		(layer "F.Cu")
		(net "M_D_CPU0_SA_DQ<30>")
	)
	(segment
		(start 266.197842 -281.678634)
		(end 265.769344 -281.678634)
		(width 0.20066)
		(layer "F.Cu")
		(net "M_D_CPU0_SA_DQ<30>")
	)
	(segment
		(start 267.724382 -281.466798)
		(end 266.409678 -281.466798)
		(width 0.20066)
		(layer "F.Cu")
		(net "M_D_CPU0_SA_DQ<30>")
	)
	(segment
		(start 261.327646 -281.466798)
		(end 260.180582 -281.466798)
		(width 0.20066)
		(layer "F.Cu")
		(net "M_D_CPU0_SA_DQ<30>")
	)
	(segment
		(start 261.762748 -281.031696)
		(end 261.327646 -281.466798)
		(width 0.20066)
		(layer "F.Cu")
		(net "M_D_CPU0_SA_DQ<30>")
	)
	(segment
		(start 265.769344 -281.678634)
		(end 265.601958 -281.511248)
		(width 0.20066)
		(layer "F.Cu")
		(net "M_D_CPU0_SA_DQ<30>")
	)
	(segment
		(start 262.51027 -281.041856)
		(end 262.50011 -281.031696)
		(width 0.101854)
		(layer "F.Cu")
		(net "M_D_CPU0_SA_DQ<30>")
	)
	(segment
		(start 265.601958 -281.511248)
		(end 265.601958 -281.18562)
		(width 0.20066)
		(layer "F.Cu")
		(net "M_D_CPU0_SA_DQ<30>")
	)
	(segment
		(start 268.829282 -281.466798)
		(end 267.724382 -281.466798)
		(width 0.20066)
		(layer "F.Cu")
		(net "M_D_CPU0_SA_DQ<30>")
	)
	(segment
		(start 262.50011 -281.031696)
		(end 261.762748 -281.031696)
		(width 0.20066)
		(layer "F.Cu")
		(net "M_D_CPU0_SA_DQ<30>")
	)
	(segment
		(start 266.409678 -281.466798)
		(end 266.197842 -281.678634)
		(width 0.20066)
		(layer "F.Cu")
		(net "M_D_CPU0_SA_DQ<30>")
	)
	(segment
		(start 265.601958 -281.18562)
		(end 265.458194 -281.041856)
		(width 0.20066)
		(layer "F.Cu")
		(net "M_D_CPU0_SA_DQ<30>")
	)
	(segment
		(start 264.825226 -281.041856)
		(end 262.765286 -281.041856)
		(width 0.1016)
		(layer "F.Cu")
		(net "M_D_CPU0_SA_DQ<30>")
	)
	(segment
		(start 262.765286 -281.041856)
		(end 262.51027 -281.041856)
		(width 0.101854)
		(layer "F.Cu")
		(net "M_D_CPU0_SA_DQ<30>")
	)
	(arc
		(start 348.412562 -266.405868)
		(mid 348.412625 -266.673838)
		(end 348.412816 -266.941808)
		(width 0.20066)
		(layer "F.Cu")
		(net "M_D_CPU0_SA_DQ<30>")
	)
	(segment
		(start 284.462728 -280.19248)
		(end 283.438346 -280.19248)
		(width 0.18288)
		(layer "In11.Cu")
		(net "M_D_CPU0_SA_DQ<30>")
	)
	(segment
		(start 332.597252 -266.382246)
		(end 332.591664 -266.376658)
		(width 0.088646)
		(layer "In11.Cu")
		(net "M_D_CPU0_SA_DQ<30>")
	)
	(segment
		(start 275.642578 -280.86558)
		(end 275.449538 -280.67254)
		(width 0.18288)
		(layer "In11.Cu")
		(net "M_D_CPU0_SA_DQ<30>")
	)
	(segment
		(start 274.748498 -281.259026)
		(end 273.450558 -281.259026)
		(width 0.18288)
		(layer "In11.Cu")
		(net "M_D_CPU0_SA_DQ<30>")
	)
	(segment
		(start 294.225218 -280.929334)
		(end 293.81831 -281.336242)
		(width 0.18288)
		(layer "In11.Cu")
		(net "M_D_CPU0_SA_DQ<30>")
	)
	(segment
		(start 311.435242 -277.932134)
		(end 310.598566 -278.76881)
		(width 0.18288)
		(layer "In11.Cu")
		(net "M_D_CPU0_SA_DQ<30>")
	)
	(segment
		(start 285.782512 -280.368502)
		(end 284.63875 -280.368502)
		(width 0.18288)
		(layer "In11.Cu")
		(net "M_D_CPU0_SA_DQ<30>")
	)
	(segment
		(start 346.838016 -266.4841)
		(end 346.837762 -266.4841)
		(width 0.088646)
		(layer "In11.Cu")
		(net "M_D_CPU0_SA_DQ<30>")
	)
	(segment
		(start 292.115494 -281.182826)
		(end 290.182808 -281.182826)
		(width 0.18288)
		(layer "In11.Cu")
		(net "M_D_CPU0_SA_DQ<30>")
	)
	(segment
		(start 278.118824 -281.17927)
		(end 278.118824 -281.012646)
		(width 0.18288)
		(layer "In11.Cu")
		(net "M_D_CPU0_SA_DQ<30>")
	)
	(segment
		(start 290.182808 -281.182826)
		(end 289.755072 -280.75509)
		(width 0.18288)
		(layer "In11.Cu")
		(net "M_D_CPU0_SA_DQ<30>")
	)
	(segment
		(start 286.869632 -280.368502)
		(end 286.676592 -280.175462)
		(width 0.18288)
		(layer "In11.Cu")
		(net "M_D_CPU0_SA_DQ<30>")
	)
	(segment
		(start 307.380894 -279.150826)
		(end 307.126894 -279.404826)
		(width 0.18288)
		(layer "In11.Cu")
		(net "M_D_CPU0_SA_DQ<30>")
	)
	(segment
		(start 293.545006 -281.336242)
		(end 293.138098 -280.929334)
		(width 0.18288)
		(layer "In11.Cu")
		(net "M_D_CPU0_SA_DQ<30>")
	)
	(segment
		(start 342.116664 -266.45235)
		(end 342.101932 -266.443714)
		(width 0.088646)
		(layer "In11.Cu")
		(net "M_D_CPU0_SA_DQ<30>")
	)
	(segment
		(start 289.755072 -280.75509)
		(end 289.755072 -280.353516)
		(width 0.18288)
		(layer "In11.Cu")
		(net "M_D_CPU0_SA_DQ<30>")
	)
	(segment
		(start 285.975552 -280.175462)
		(end 285.782512 -280.368502)
		(width 0.18288)
		(layer "In11.Cu")
		(net "M_D_CPU0_SA_DQ<30>")
	)
	(segment
		(start 303.799494 -279.404826)
		(end 302.834294 -280.370026)
		(width 0.18288)
		(layer "In11.Cu")
		(net "M_D_CPU0_SA_DQ<30>")
	)
	(segment
		(start 314.766452 -277.277322)
		(end 314.11164 -277.932134)
		(width 0.18288)
		(layer "In11.Cu")
		(net "M_D_CPU0_SA_DQ<30>")
	)
	(segment
		(start 279.353518 -280.852626)
		(end 278.993346 -280.852626)
		(width 0.18288)
		(layer "In11.Cu")
		(net "M_D_CPU0_SA_DQ<30>")
	)
	(segment
		(start 289.755072 -280.353516)
		(end 289.517582 -280.116026)
		(width 0.18288)
		(layer "In11.Cu")
		(net "M_D_CPU0_SA_DQ<30>")
	)
	(segment
		(start 293.138098 -280.929334)
		(end 292.368986 -280.929334)
		(width 0.18288)
		(layer "In11.Cu")
		(net "M_D_CPU0_SA_DQ<30>")
	)
	(segment
		(start 292.368986 -280.929334)
		(end 292.115494 -281.182826)
		(width 0.18288)
		(layer "In11.Cu")
		(net "M_D_CPU0_SA_DQ<30>")
	)
	(segment
		(start 286.483552 -279.736042)
		(end 286.168592 -279.736042)
		(width 0.18288)
		(layer "In11.Cu")
		(net "M_D_CPU0_SA_DQ<30>")
	)
	(segment
		(start 309.958486 -278.76881)
		(end 309.373016 -278.18334)
		(width 0.18288)
		(layer "In11.Cu")
		(net "M_D_CPU0_SA_DQ<30>")
	)
	(segment
		(start 304.992532 -279.211786)
		(end 304.799492 -279.404826)
		(width 0.18288)
		(layer "In11.Cu")
		(net "M_D_CPU0_SA_DQ<30>")
	)
	(segment
		(start 332.041754 -266.376658)
		(end 331.546454 -266.871958)
		(width 0.088646)
		(layer "In11.Cu")
		(net "M_D_CPU0_SA_DQ<30>")
	)
	(segment
		(start 274.941538 -280.86558)
		(end 274.941538 -281.065986)
		(width 0.18288)
		(layer "In11.Cu")
		(net "M_D_CPU0_SA_DQ<30>")
	)
	(segment
		(start 347.847666 -266.506198)
		(end 347.755464 -266.45235)
		(width 0.088646)
		(layer "In11.Cu")
		(net "M_D_CPU0_SA_DQ<30>")
	)
	(segment
		(start 295.660826 -281.042618)
		(end 294.631618 -281.042618)
		(width 0.18288)
		(layer "In11.Cu")
		(net "M_D_CPU0_SA_DQ<30>")
	)
	(segment
		(start 293.81831 -281.336242)
		(end 293.545006 -281.336242)
		(width 0.18288)
		(layer "In11.Cu")
		(net "M_D_CPU0_SA_DQ<30>")
	)
	(segment
		(start 309.373016 -278.18334)
		(end 309.037228 -278.18334)
		(width 0.18288)
		(layer "In11.Cu")
		(net "M_D_CPU0_SA_DQ<30>")
	)
	(segment
		(start 274.941538 -281.065986)
		(end 274.748498 -281.259026)
		(width 0.18288)
		(layer "In11.Cu")
		(net "M_D_CPU0_SA_DQ<30>")
	)
	(segment
		(start 278.118824 -281.012646)
		(end 277.958804 -280.852626)
		(width 0.18288)
		(layer "In11.Cu")
		(net "M_D_CPU0_SA_DQ<30>")
	)
	(segment
		(start 286.676592 -279.929082)
		(end 286.483552 -279.736042)
		(width 0.18288)
		(layer "In11.Cu")
		(net "M_D_CPU0_SA_DQ<30>")
	)
	(segment
		(start 286.676592 -280.175462)
		(end 286.676592 -279.929082)
		(width 0.18288)
		(layer "In11.Cu")
		(net "M_D_CPU0_SA_DQ<30>")
	)
	(segment
		(start 294.518334 -280.929334)
		(end 294.225218 -280.929334)
		(width 0.18288)
		(layer "In11.Cu")
		(net "M_D_CPU0_SA_DQ<30>")
	)
	(segment
		(start 314.11164 -277.932134)
		(end 311.435242 -277.932134)
		(width 0.18288)
		(layer "In11.Cu")
		(net "M_D_CPU0_SA_DQ<30>")
	)
	(segment
		(start 298.93514 -280.190956)
		(end 298.933362 -280.192734)
		(width 0.18288)
		(layer "In11.Cu")
		(net "M_D_CPU0_SA_DQ<30>")
	)
	(segment
		(start 298.933362 -280.192734)
		(end 298.210986 -280.192734)
		(width 0.18288)
		(layer "In11.Cu")
		(net "M_D_CPU0_SA_DQ<30>")
	)
	(segment
		(start 331.546454 -267.208508)
		(end 331.19695 -267.558012)
		(width 0.088646)
		(layer "In11.Cu")
		(net "M_D_CPU0_SA_DQ<30>")
	)
	(segment
		(start 310.598566 -278.76881)
		(end 309.958486 -278.76881)
		(width 0.18288)
		(layer "In11.Cu")
		(net "M_D_CPU0_SA_DQ<30>")
	)
	(segment
		(start 278.833326 -281.212544)
		(end 278.673306 -281.372564)
		(width 0.18288)
		(layer "In11.Cu")
		(net "M_D_CPU0_SA_DQ<30>")
	)
	(segment
		(start 308.069742 -279.150826)
		(end 307.380894 -279.150826)
		(width 0.18288)
		(layer "In11.Cu")
		(net "M_D_CPU0_SA_DQ<30>")
	)
	(segment
		(start 294.631618 -281.042618)
		(end 294.518334 -280.929334)
		(width 0.18288)
		(layer "In11.Cu")
		(net "M_D_CPU0_SA_DQ<30>")
	)
	(segment
		(start 277.104094 -280.852626)
		(end 276.697694 -281.259026)
		(width 0.18288)
		(layer "In11.Cu")
		(net "M_D_CPU0_SA_DQ<30>")
	)
	(segment
		(start 278.312118 -281.372564)
		(end 278.118824 -281.17927)
		(width 0.18288)
		(layer "In11.Cu")
		(net "M_D_CPU0_SA_DQ<30>")
	)
	(segment
		(start 332.718664 -266.45235)
		(end 332.597252 -266.382246)
		(width 0.088646)
		(layer "In11.Cu")
		(net "M_D_CPU0_SA_DQ<30>")
	)
	(segment
		(start 280.849324 -281.245818)
		(end 280.646124 -281.042618)
		(width 0.18288)
		(layer "In11.Cu")
		(net "M_D_CPU0_SA_DQ<30>")
	)
	(segment
		(start 325.133208 -267.749274)
		(end 315.60516 -277.277322)
		(width 0.18288)
		(layer "In11.Cu")
		(net "M_D_CPU0_SA_DQ<30>")
	)
	(segment
		(start 269.42669 -282.064206)
		(end 268.829282 -281.466798)
		(width 0.18288)
		(layer "In11.Cu")
		(net "M_D_CPU0_SA_DQ<30>")
	)
	(segment
		(start 295.742106 -281.123898)
		(end 295.660826 -281.042618)
		(width 0.18288)
		(layer "In11.Cu")
		(net "M_D_CPU0_SA_DQ<30>")
	)
	(segment
		(start 284.63875 -280.368502)
		(end 284.462728 -280.19248)
		(width 0.18288)
		(layer "In11.Cu")
		(net "M_D_CPU0_SA_DQ<30>")
	)
	(segment
		(start 305.185572 -278.855678)
		(end 304.992532 -279.048718)
		(width 0.18288)
		(layer "In11.Cu")
		(net "M_D_CPU0_SA_DQ<30>")
	)
	(segment
		(start 347.19006 -266.45235)
		(end 347.135196 -266.4841)
		(width 0.088646)
		(layer "In11.Cu")
		(net "M_D_CPU0_SA_DQ<30>")
	)
	(segment
		(start 307.126894 -279.404826)
		(end 305.886612 -279.404826)
		(width 0.18288)
		(layer "In11.Cu")
		(net "M_D_CPU0_SA_DQ<30>")
	)
	(segment
		(start 304.992532 -279.048718)
		(end 304.992532 -279.211786)
		(width 0.18288)
		(layer "In11.Cu")
		(net "M_D_CPU0_SA_DQ<30>")
	)
	(segment
		(start 301.737522 -280.176986)
		(end 301.737522 -279.906984)
		(width 0.18288)
		(layer "In11.Cu")
		(net "M_D_CPU0_SA_DQ<30>")
	)
	(segment
		(start 330.903072 -267.749274)
		(end 325.133208 -267.749274)
		(width 0.18288)
		(layer "In11.Cu")
		(net "M_D_CPU0_SA_DQ<30>")
	)
	(segment
		(start 331.546454 -266.871958)
		(end 331.546454 -267.208508)
		(width 0.088646)
		(layer "In11.Cu")
		(net "M_D_CPU0_SA_DQ<30>")
	)
	(segment
		(start 305.886612 -279.404826)
		(end 305.693572 -279.211786)
		(width 0.18288)
		(layer "In11.Cu")
		(net "M_D_CPU0_SA_DQ<30>")
	)
	(segment
		(start 309.037228 -278.18334)
		(end 308.069742 -279.150826)
		(width 0.18288)
		(layer "In11.Cu")
		(net "M_D_CPU0_SA_DQ<30>")
	)
	(segment
		(start 282.385008 -281.245818)
		(end 280.849324 -281.245818)
		(width 0.18288)
		(layer "In11.Cu")
		(net "M_D_CPU0_SA_DQ<30>")
	)
	(segment
		(start 347.755464 -266.45235)
		(end 347.740732 -266.443714)
		(width 0.088646)
		(layer "In11.Cu")
		(net "M_D_CPU0_SA_DQ<30>")
	)
	(segment
		(start 300.843442 -280.370026)
		(end 300.040294 -280.370026)
		(width 0.18288)
		(layer "In11.Cu")
		(net "M_D_CPU0_SA_DQ<30>")
	)
	(segment
		(start 315.60516 -277.277322)
		(end 314.766452 -277.277322)
		(width 0.18288)
		(layer "In11.Cu")
		(net "M_D_CPU0_SA_DQ<30>")
	)
	(segment
		(start 285.975552 -279.929082)
		(end 285.975552 -280.175462)
		(width 0.18288)
		(layer "In11.Cu")
		(net "M_D_CPU0_SA_DQ<30>")
	)
	(segment
		(start 305.500532 -278.855678)
		(end 305.185572 -278.855678)
		(width 0.18288)
		(layer "In11.Cu")
		(net "M_D_CPU0_SA_DQ<30>")
	)
	(segment
		(start 305.693572 -279.048718)
		(end 305.500532 -278.855678)
		(width 0.18288)
		(layer "In11.Cu")
		(net "M_D_CPU0_SA_DQ<30>")
	)
	(segment
		(start 289.517582 -280.116026)
		(end 288.356294 -280.116026)
		(width 0.18288)
		(layer "In11.Cu")
		(net "M_D_CPU0_SA_DQ<30>")
	)
	(segment
		(start 276.697694 -281.259026)
		(end 275.835618 -281.259026)
		(width 0.18288)
		(layer "In11.Cu")
		(net "M_D_CPU0_SA_DQ<30>")
	)
	(segment
		(start 299.863002 -280.192734)
		(end 299.078904 -280.192734)
		(width 0.18288)
		(layer "In11.Cu")
		(net "M_D_CPU0_SA_DQ<30>")
	)
	(segment
		(start 279.54351 -281.042618)
		(end 279.353518 -280.852626)
		(width 0.18288)
		(layer "In11.Cu")
		(net "M_D_CPU0_SA_DQ<30>")
	)
	(segment
		(start 346.837762 -266.4841)
		(end 346.764864 -266.444222)
		(width 0.088646)
		(layer "In11.Cu")
		(net "M_D_CPU0_SA_DQ<30>")
	)
	(segment
		(start 275.449538 -280.67254)
		(end 275.134578 -280.67254)
		(width 0.18288)
		(layer "In11.Cu")
		(net "M_D_CPU0_SA_DQ<30>")
	)
	(segment
		(start 273.450558 -281.259026)
		(end 272.645378 -282.064206)
		(width 0.18288)
		(layer "In11.Cu")
		(net "M_D_CPU0_SA_DQ<30>")
	)
	(segment
		(start 275.134578 -280.67254)
		(end 274.941538 -280.86558)
		(width 0.18288)
		(layer "In11.Cu")
		(net "M_D_CPU0_SA_DQ<30>")
	)
	(segment
		(start 297.279822 -281.123898)
		(end 295.742106 -281.123898)
		(width 0.18288)
		(layer "In11.Cu")
		(net "M_D_CPU0_SA_DQ<30>")
	)
	(segment
		(start 344.936064 -266.45235)
		(end 344.921332 -266.443714)
		(width 0.088646)
		(layer "In11.Cu")
		(net "M_D_CPU0_SA_DQ<30>")
	)
	(segment
		(start 301.930562 -280.370026)
		(end 301.737522 -280.176986)
		(width 0.18288)
		(layer "In11.Cu")
		(net "M_D_CPU0_SA_DQ<30>")
	)
	(segment
		(start 299.077126 -280.190956)
		(end 298.93514 -280.190956)
		(width 0.18288)
		(layer "In11.Cu")
		(net "M_D_CPU0_SA_DQ<30>")
	)
	(segment
		(start 332.591664 -266.376658)
		(end 332.041754 -266.376658)
		(width 0.088646)
		(layer "In11.Cu")
		(net "M_D_CPU0_SA_DQ<30>")
	)
	(segment
		(start 288.103818 -280.368502)
		(end 286.869632 -280.368502)
		(width 0.18288)
		(layer "In11.Cu")
		(net "M_D_CPU0_SA_DQ<30>")
	)
	(segment
		(start 340.237064 -266.45235)
		(end 340.222332 -266.443714)
		(width 0.088646)
		(layer "In11.Cu")
		(net "M_D_CPU0_SA_DQ<30>")
	)
	(segment
		(start 305.693572 -279.211786)
		(end 305.693572 -279.048718)
		(width 0.18288)
		(layer "In11.Cu")
		(net "M_D_CPU0_SA_DQ<30>")
	)
	(segment
		(start 278.993346 -280.852626)
		(end 278.833326 -281.012646)
		(width 0.18288)
		(layer "In11.Cu")
		(net "M_D_CPU0_SA_DQ<30>")
	)
	(segment
		(start 280.646124 -281.042618)
		(end 279.54351 -281.042618)
		(width 0.18288)
		(layer "In11.Cu")
		(net "M_D_CPU0_SA_DQ<30>")
	)
	(segment
		(start 304.799492 -279.404826)
		(end 303.799494 -279.404826)
		(width 0.18288)
		(layer "In11.Cu")
		(net "M_D_CPU0_SA_DQ<30>")
	)
	(segment
		(start 331.108304 -267.749274)
		(end 330.903072 -267.749274)
		(width 0.088646)
		(layer "In11.Cu")
		(net "M_D_CPU0_SA_DQ<30>")
	)
	(segment
		(start 343.056464 -266.45235)
		(end 343.041732 -266.443714)
		(width 0.088646)
		(layer "In11.Cu")
		(net "M_D_CPU0_SA_DQ<30>")
	)
	(segment
		(start 288.356294 -280.116026)
		(end 288.103818 -280.368502)
		(width 0.18288)
		(layer "In11.Cu")
		(net "M_D_CPU0_SA_DQ<30>")
	)
	(segment
		(start 331.19695 -267.558012)
		(end 331.19695 -267.660628)
		(width 0.088646)
		(layer "In11.Cu")
		(net "M_D_CPU0_SA_DQ<30>")
	)
	(segment
		(start 302.834294 -280.370026)
		(end 301.930562 -280.370026)
		(width 0.18288)
		(layer "In11.Cu")
		(net "M_D_CPU0_SA_DQ<30>")
	)
	(segment
		(start 301.036482 -279.906984)
		(end 301.036482 -280.176986)
		(width 0.18288)
		(layer "In11.Cu")
		(net "M_D_CPU0_SA_DQ<30>")
	)
	(segment
		(start 286.168592 -279.736042)
		(end 285.975552 -279.929082)
		(width 0.18288)
		(layer "In11.Cu")
		(net "M_D_CPU0_SA_DQ<30>")
	)
	(segment
		(start 301.544482 -279.713944)
		(end 301.229522 -279.713944)
		(width 0.18288)
		(layer "In11.Cu")
		(net "M_D_CPU0_SA_DQ<30>")
	)
	(segment
		(start 343.996264 -266.45235)
		(end 343.981532 -266.443714)
		(width 0.088646)
		(layer "In11.Cu")
		(net "M_D_CPU0_SA_DQ<30>")
	)
	(segment
		(start 278.673306 -281.372564)
		(end 278.312118 -281.372564)
		(width 0.18288)
		(layer "In11.Cu")
		(net "M_D_CPU0_SA_DQ<30>")
	)
	(segment
		(start 283.438346 -280.19248)
		(end 282.385008 -281.245818)
		(width 0.18288)
		(layer "In11.Cu")
		(net "M_D_CPU0_SA_DQ<30>")
	)
	(segment
		(start 301.229522 -279.713944)
		(end 301.036482 -279.906984)
		(width 0.18288)
		(layer "In11.Cu")
		(net "M_D_CPU0_SA_DQ<30>")
	)
	(segment
		(start 300.040294 -280.370026)
		(end 299.863002 -280.192734)
		(width 0.18288)
		(layer "In11.Cu")
		(net "M_D_CPU0_SA_DQ<30>")
	)
	(segment
		(start 301.036482 -280.176986)
		(end 300.843442 -280.370026)
		(width 0.18288)
		(layer "In11.Cu")
		(net "M_D_CPU0_SA_DQ<30>")
	)
	(segment
		(start 341.176864 -266.45235)
		(end 341.162132 -266.443714)
		(width 0.088646)
		(layer "In11.Cu")
		(net "M_D_CPU0_SA_DQ<30>")
	)
	(segment
		(start 275.642578 -281.065986)
		(end 275.642578 -280.86558)
		(width 0.18288)
		(layer "In11.Cu")
		(net "M_D_CPU0_SA_DQ<30>")
	)
	(segment
		(start 277.958804 -280.852626)
		(end 277.104094 -280.852626)
		(width 0.18288)
		(layer "In11.Cu")
		(net "M_D_CPU0_SA_DQ<30>")
	)
	(segment
		(start 298.210986 -280.192734)
		(end 297.279822 -281.123898)
		(width 0.18288)
		(layer "In11.Cu")
		(net "M_D_CPU0_SA_DQ<30>")
	)
	(segment
		(start 331.19695 -267.660628)
		(end 331.108304 -267.749274)
		(width 0.088646)
		(layer "In11.Cu")
		(net "M_D_CPU0_SA_DQ<30>")
	)
	(segment
		(start 275.835618 -281.259026)
		(end 275.642578 -281.065986)
		(width 0.18288)
		(layer "In11.Cu")
		(net "M_D_CPU0_SA_DQ<30>")
	)
	(segment
		(start 272.645378 -282.064206)
		(end 269.42669 -282.064206)
		(width 0.18288)
		(layer "In11.Cu")
		(net "M_D_CPU0_SA_DQ<30>")
	)
	(segment
		(start 278.833326 -281.012646)
		(end 278.833326 -281.212544)
		(width 0.18288)
		(layer "In11.Cu")
		(net "M_D_CPU0_SA_DQ<30>")
	)
	(segment
		(start 299.078904 -280.192734)
		(end 299.077126 -280.190956)
		(width 0.18288)
		(layer "In11.Cu")
		(net "M_D_CPU0_SA_DQ<30>")
	)
	(segment
		(start 301.737522 -279.906984)
		(end 301.544482 -279.713944)
		(width 0.18288)
		(layer "In11.Cu")
		(net "M_D_CPU0_SA_DQ<30>")
	)
	(arc
		(start 337.417664 -266.45235)
		(mid 337.134962 -266.376574)
		(end 336.85226 -266.45235)
		(width 0.088646)
		(layer "In11.Cu")
		(net "M_D_CPU0_SA_DQ<30>")
	)
	(arc
		(start 344.921332 -266.443714)
		(mid 344.644857 -266.376394)
		(end 344.37066 -266.45235)
		(width 0.088646)
		(layer "In11.Cu")
		(net "M_D_CPU0_SA_DQ<30>")
	)
	(arc
		(start 333.658464 -266.45235)
		(mid 333.375762 -266.376574)
		(end 333.09306 -266.45235)
		(width 0.088646)
		(layer "In11.Cu")
		(net "M_D_CPU0_SA_DQ<30>")
	)
	(arc
		(start 348.412816 -266.941808)
		(mid 348.144273 -266.705798)
		(end 347.847666 -266.506198)
		(width 0.088646)
		(layer "In11.Cu")
		(net "M_D_CPU0_SA_DQ<30>")
	)
	(arc
		(start 343.041732 -266.443714)
		(mid 342.765257 -266.376394)
		(end 342.49106 -266.45235)
		(width 0.088646)
		(layer "In11.Cu")
		(net "M_D_CPU0_SA_DQ<30>")
	)
	(arc
		(start 334.03286 -266.45235)
		(mid 333.845662 -266.502527)
		(end 333.658464 -266.45235)
		(width 0.088646)
		(layer "In11.Cu")
		(net "M_D_CPU0_SA_DQ<30>")
	)
	(arc
		(start 343.981532 -266.443714)
		(mid 343.705057 -266.376394)
		(end 343.43086 -266.45235)
		(width 0.088646)
		(layer "In11.Cu")
		(net "M_D_CPU0_SA_DQ<30>")
	)
	(arc
		(start 333.09306 -266.45235)
		(mid 332.905862 -266.502527)
		(end 332.718664 -266.45235)
		(width 0.088646)
		(layer "In11.Cu")
		(net "M_D_CPU0_SA_DQ<30>")
	)
	(arc
		(start 345.31046 -266.45235)
		(mid 345.123262 -266.502527)
		(end 344.936064 -266.45235)
		(width 0.088646)
		(layer "In11.Cu")
		(net "M_D_CPU0_SA_DQ<30>")
	)
	(arc
		(start 347.740732 -266.443714)
		(mid 347.464257 -266.376394)
		(end 347.19006 -266.45235)
		(width 0.088646)
		(layer "In11.Cu")
		(net "M_D_CPU0_SA_DQ<30>")
	)
	(arc
		(start 346.764864 -266.444222)
		(mid 346.506516 -266.381444)
		(end 346.25026 -266.45235)
		(width 0.088646)
		(layer "In11.Cu")
		(net "M_D_CPU0_SA_DQ<30>")
	)
	(arc
		(start 336.477864 -266.45235)
		(mid 336.195162 -266.376574)
		(end 335.91246 -266.45235)
		(width 0.088646)
		(layer "In11.Cu")
		(net "M_D_CPU0_SA_DQ<30>")
	)
	(arc
		(start 342.49106 -266.45235)
		(mid 342.303862 -266.502527)
		(end 342.116664 -266.45235)
		(width 0.088646)
		(layer "In11.Cu")
		(net "M_D_CPU0_SA_DQ<30>")
	)
	(arc
		(start 340.61146 -266.45235)
		(mid 340.424262 -266.502527)
		(end 340.237064 -266.45235)
		(width 0.088646)
		(layer "In11.Cu")
		(net "M_D_CPU0_SA_DQ<30>")
	)
	(arc
		(start 335.538064 -266.45235)
		(mid 335.255362 -266.376574)
		(end 334.97266 -266.45235)
		(width 0.088646)
		(layer "In11.Cu")
		(net "M_D_CPU0_SA_DQ<30>")
	)
	(arc
		(start 346.25026 -266.45235)
		(mid 346.063062 -266.502527)
		(end 345.875864 -266.45235)
		(width 0.088646)
		(layer "In11.Cu")
		(net "M_D_CPU0_SA_DQ<30>")
	)
	(arc
		(start 342.101932 -266.443714)
		(mid 341.825457 -266.376394)
		(end 341.55126 -266.45235)
		(width 0.088646)
		(layer "In11.Cu")
		(net "M_D_CPU0_SA_DQ<30>")
	)
	(arc
		(start 336.85226 -266.45235)
		(mid 336.665062 -266.502527)
		(end 336.477864 -266.45235)
		(width 0.088646)
		(layer "In11.Cu")
		(net "M_D_CPU0_SA_DQ<30>")
	)
	(arc
		(start 335.91246 -266.45235)
		(mid 335.725262 -266.502527)
		(end 335.538064 -266.45235)
		(width 0.088646)
		(layer "In11.Cu")
		(net "M_D_CPU0_SA_DQ<30>")
	)
	(arc
		(start 341.162132 -266.443714)
		(mid 340.885657 -266.376394)
		(end 340.61146 -266.45235)
		(width 0.088646)
		(layer "In11.Cu")
		(net "M_D_CPU0_SA_DQ<30>")
	)
	(arc
		(start 347.135196 -266.4841)
		(mid 346.986606 -266.523923)
		(end 346.838016 -266.4841)
		(width 0.088646)
		(layer "In11.Cu")
		(net "M_D_CPU0_SA_DQ<30>")
	)
	(arc
		(start 339.67166 -266.45235)
		(mid 339.484462 -266.502527)
		(end 339.297264 -266.45235)
		(width 0.088646)
		(layer "In11.Cu")
		(net "M_D_CPU0_SA_DQ<30>")
	)
	(arc
		(start 334.598264 -266.45235)
		(mid 334.315562 -266.376574)
		(end 334.03286 -266.45235)
		(width 0.088646)
		(layer "In11.Cu")
		(net "M_D_CPU0_SA_DQ<30>")
	)
	(arc
		(start 340.222332 -266.443714)
		(mid 339.945857 -266.376394)
		(end 339.67166 -266.45235)
		(width 0.088646)
		(layer "In11.Cu")
		(net "M_D_CPU0_SA_DQ<30>")
	)
	(arc
		(start 343.43086 -266.45235)
		(mid 343.243662 -266.502527)
		(end 343.056464 -266.45235)
		(width 0.088646)
		(layer "In11.Cu")
		(net "M_D_CPU0_SA_DQ<30>")
	)
	(arc
		(start 344.37066 -266.45235)
		(mid 344.183462 -266.502527)
		(end 343.996264 -266.45235)
		(width 0.088646)
		(layer "In11.Cu")
		(net "M_D_CPU0_SA_DQ<30>")
	)
	(arc
		(start 341.55126 -266.45235)
		(mid 341.364062 -266.502527)
		(end 341.176864 -266.45235)
		(width 0.088646)
		(layer "In11.Cu")
		(net "M_D_CPU0_SA_DQ<30>")
	)
	(arc
		(start 338.73186 -266.45235)
		(mid 338.544662 -266.502527)
		(end 338.357464 -266.45235)
		(width 0.088646)
		(layer "In11.Cu")
		(net "M_D_CPU0_SA_DQ<30>")
	)
	(arc
		(start 334.97266 -266.45235)
		(mid 334.785462 -266.502527)
		(end 334.598264 -266.45235)
		(width 0.088646)
		(layer "In11.Cu")
		(net "M_D_CPU0_SA_DQ<30>")
	)
	(arc
		(start 339.297264 -266.45235)
		(mid 339.014562 -266.376574)
		(end 338.73186 -266.45235)
		(width 0.088646)
		(layer "In11.Cu")
		(net "M_D_CPU0_SA_DQ<30>")
	)
	(arc
		(start 337.79206 -266.45235)
		(mid 337.604862 -266.502527)
		(end 337.417664 -266.45235)
		(width 0.088646)
		(layer "In11.Cu")
		(net "M_D_CPU0_SA_DQ<30>")
	)
	(arc
		(start 338.357464 -266.45235)
		(mid 338.074762 -266.376574)
		(end 337.79206 -266.45235)
		(width 0.088646)
		(layer "In11.Cu")
		(net "M_D_CPU0_SA_DQ<30>")
	)
	(arc
		(start 345.875864 -266.45235)
		(mid 345.593162 -266.376574)
		(end 345.31046 -266.45235)
		(width 0.088646)
		(layer "In11.Cu")
		(net "M_D_CPU0_SA_DQ<30>")
	)
	(segment
		(start 268.829282 -315.46673)
		(end 267.724382 -315.46673)
		(width 0.20066)
		(layer "F.Cu")
		(net "M_D_CPU0_SA_DQ<2>")
	)
	(segment
		(start 262.765286 -315.041788)
		(end 262.51027 -315.041788)
		(width 0.101854)
		(layer "F.Cu")
		(net "M_D_CPU0_SA_DQ<2>")
	)
	(segment
		(start 261.327646 -315.46673)
		(end 260.180582 -315.46673)
		(width 0.20066)
		(layer "F.Cu")
		(net "M_D_CPU0_SA_DQ<2>")
	)
	(segment
		(start 261.762748 -315.031628)
		(end 261.327646 -315.46673)
		(width 0.20066)
		(layer "F.Cu")
		(net "M_D_CPU0_SA_DQ<2>")
	)
	(segment
		(start 344.653362 -276.708362)
		(end 344.653616 -276.708616)
		(width 0.20066)
		(layer "F.Cu")
		(net "M_D_CPU0_SA_DQ<2>")
	)
	(segment
		(start 265.458194 -315.041788)
		(end 264.825226 -315.041788)
		(width 0.20066)
		(layer "F.Cu")
		(net "M_D_CPU0_SA_DQ<2>")
	)
	(segment
		(start 267.724382 -315.46673)
		(end 266.409678 -315.46673)
		(width 0.20066)
		(layer "F.Cu")
		(net "M_D_CPU0_SA_DQ<2>")
	)
	(segment
		(start 262.50011 -315.031628)
		(end 261.762748 -315.031628)
		(width 0.20066)
		(layer "F.Cu")
		(net "M_D_CPU0_SA_DQ<2>")
	)
	(segment
		(start 266.409678 -315.46673)
		(end 266.197842 -315.678566)
		(width 0.20066)
		(layer "F.Cu")
		(net "M_D_CPU0_SA_DQ<2>")
	)
	(segment
		(start 265.601958 -315.185552)
		(end 265.458194 -315.041788)
		(width 0.20066)
		(layer "F.Cu")
		(net "M_D_CPU0_SA_DQ<2>")
	)
	(segment
		(start 264.825226 -315.041788)
		(end 262.765286 -315.041788)
		(width 0.1016)
		(layer "F.Cu")
		(net "M_D_CPU0_SA_DQ<2>")
	)
	(segment
		(start 265.769344 -315.678566)
		(end 265.601958 -315.51118)
		(width 0.20066)
		(layer "F.Cu")
		(net "M_D_CPU0_SA_DQ<2>")
	)
	(segment
		(start 266.197842 -315.678566)
		(end 265.769344 -315.678566)
		(width 0.20066)
		(layer "F.Cu")
		(net "M_D_CPU0_SA_DQ<2>")
	)
	(segment
		(start 344.653362 -276.172676)
		(end 344.653362 -276.708362)
		(width 0.20066)
		(layer "F.Cu")
		(net "M_D_CPU0_SA_DQ<2>")
	)
	(segment
		(start 262.51027 -315.041788)
		(end 262.50011 -315.031628)
		(width 0.101854)
		(layer "F.Cu")
		(net "M_D_CPU0_SA_DQ<2>")
	)
	(segment
		(start 265.601958 -315.51118)
		(end 265.601958 -315.185552)
		(width 0.20066)
		(layer "F.Cu")
		(net "M_D_CPU0_SA_DQ<2>")
	)
	(segment
		(start 277.705312 -316.741556)
		(end 276.65045 -315.686694)
		(width 0.18288)
		(layer "In6.Cu")
		(net "M_D_CPU0_SA_DQ<2>")
	)
	(segment
		(start 341.096346 -277.024338)
		(end 341.081614 -277.032974)
		(width 0.088646)
		(layer "In6.Cu")
		(net "M_D_CPU0_SA_DQ<2>")
	)
	(segment
		(start 342.036146 -277.024338)
		(end 342.021414 -277.032974)
		(width 0.088646)
		(layer "In6.Cu")
		(net "M_D_CPU0_SA_DQ<2>")
	)
	(segment
		(start 295.209468 -313.34202)
		(end 294.27932 -313.34202)
		(width 0.18288)
		(layer "In6.Cu")
		(net "M_D_CPU0_SA_DQ<2>")
	)
	(segment
		(start 297.123358 -311.492138)
		(end 297.123358 -311.718198)
		(width 0.18288)
		(layer "In6.Cu")
		(net "M_D_CPU0_SA_DQ<2>")
	)
	(segment
		(start 344.340942 -276.708616)
		(end 344.275156 -276.64283)
		(width 0.088646)
		(layer "In6.Cu")
		(net "M_D_CPU0_SA_DQ<2>")
	)
	(segment
		(start 333.57185 -281.911298)
		(end 333.56296 -281.916378)
		(width 0.088646)
		(layer "In6.Cu")
		(net "M_D_CPU0_SA_DQ<2>")
	)
	(segment
		(start 334.51165 -280.283412)
		(end 334.50276 -280.288492)
		(width 0.088646)
		(layer "In6.Cu")
		(net "M_D_CPU0_SA_DQ<2>")
	)
	(segment
		(start 282.80868 -317.646812)
		(end 281.903424 -316.741556)
		(width 0.18288)
		(layer "In6.Cu")
		(net "M_D_CPU0_SA_DQ<2>")
	)
	(segment
		(start 275.693632 -315.686694)
		(end 275.510752 -315.503814)
		(width 0.18288)
		(layer "In6.Cu")
		(net "M_D_CPU0_SA_DQ<2>")
	)
	(segment
		(start 281.903424 -316.741556)
		(end 277.705312 -316.741556)
		(width 0.18288)
		(layer "In6.Cu")
		(net "M_D_CPU0_SA_DQ<2>")
	)
	(segment
		(start 317.744348 -299.122592)
		(end 315.137546 -301.729394)
		(width 0.18288)
		(layer "In6.Cu")
		(net "M_D_CPU0_SA_DQ<2>")
	)
	(segment
		(start 274.819872 -315.503814)
		(end 274.636992 -315.686694)
		(width 0.18288)
		(layer "In6.Cu")
		(net "M_D_CPU0_SA_DQ<2>")
	)
	(segment
		(start 342.970104 -277.027894)
		(end 342.961214 -277.032974)
		(width 0.088646)
		(layer "In6.Cu")
		(net "M_D_CPU0_SA_DQ<2>")
	)
	(segment
		(start 271.376648 -315.539628)
		(end 271.051528 -315.539628)
		(width 0.18288)
		(layer "In6.Cu")
		(net "M_D_CPU0_SA_DQ<2>")
	)
	(segment
		(start 340.156546 -277.024338)
		(end 340.141814 -277.032974)
		(width 0.088646)
		(layer "In6.Cu")
		(net "M_D_CPU0_SA_DQ<2>")
	)
	(segment
		(start 275.510752 -315.503814)
		(end 275.510752 -314.891928)
		(width 0.18288)
		(layer "In6.Cu")
		(net "M_D_CPU0_SA_DQ<2>")
	)
	(segment
		(start 275.510752 -314.891928)
		(end 275.327872 -314.709048)
		(width 0.18288)
		(layer "In6.Cu")
		(net "M_D_CPU0_SA_DQ<2>")
	)
	(segment
		(start 291.828728 -313.990228)
		(end 291.085524 -313.990228)
		(width 0.18288)
		(layer "In6.Cu")
		(net "M_D_CPU0_SA_DQ<2>")
	)
	(segment
		(start 275.327872 -314.709048)
		(end 275.002752 -314.709048)
		(width 0.18288)
		(layer "In6.Cu")
		(net "M_D_CPU0_SA_DQ<2>")
	)
	(segment
		(start 270.685768 -316.063884)
		(end 269.426436 -316.063884)
		(width 0.18288)
		(layer "In6.Cu")
		(net "M_D_CPU0_SA_DQ<2>")
	)
	(segment
		(start 270.868648 -315.722508)
		(end 270.868648 -315.881004)
		(width 0.18288)
		(layer "In6.Cu")
		(net "M_D_CPU0_SA_DQ<2>")
	)
	(segment
		(start 274.819872 -314.891928)
		(end 274.819872 -315.503814)
		(width 0.18288)
		(layer "In6.Cu")
		(net "M_D_CPU0_SA_DQ<2>")
	)
	(segment
		(start 293.95928 -312.735722)
		(end 293.5859 -312.735722)
		(width 0.18288)
		(layer "In6.Cu")
		(net "M_D_CPU0_SA_DQ<2>")
	)
	(segment
		(start 333.750412 -281.582114)
		(end 333.750412 -281.59202)
		(width 0.088646)
		(layer "In6.Cu")
		(net "M_D_CPU0_SA_DQ<2>")
	)
	(segment
		(start 276.65045 -315.686694)
		(end 275.693632 -315.686694)
		(width 0.18288)
		(layer "In6.Cu")
		(net "M_D_CPU0_SA_DQ<2>")
	)
	(segment
		(start 275.002752 -314.709048)
		(end 274.819872 -314.891928)
		(width 0.18288)
		(layer "In6.Cu")
		(net "M_D_CPU0_SA_DQ<2>")
	)
	(segment
		(start 314.4901 -303.141888)
		(end 313.45759 -303.141888)
		(width 0.18288)
		(layer "In6.Cu")
		(net "M_D_CPU0_SA_DQ<2>")
	)
	(segment
		(start 293.5859 -312.735722)
		(end 293.42588 -312.895742)
		(width 0.18288)
		(layer "In6.Cu")
		(net "M_D_CPU0_SA_DQ<2>")
	)
	(segment
		(start 300.531784 -309.941722)
		(end 298.673774 -309.941722)
		(width 0.18288)
		(layer "In6.Cu")
		(net "M_D_CPU0_SA_DQ<2>")
	)
	(segment
		(start 338.449412 -278.322278)
		(end 338.449412 -278.336502)
		(width 0.088646)
		(layer "In6.Cu")
		(net "M_D_CPU0_SA_DQ<2>")
	)
	(segment
		(start 271.559528 -315.881004)
		(end 271.559528 -315.722508)
		(width 0.18288)
		(layer "In6.Cu")
		(net "M_D_CPU0_SA_DQ<2>")
	)
	(segment
		(start 333.280512 -282.438094)
		(end 332.842616 -282.87599)
		(width 0.088646)
		(layer "In6.Cu")
		(net "M_D_CPU0_SA_DQ<2>")
	)
	(segment
		(start 270.868648 -315.881004)
		(end 270.685768 -316.063884)
		(width 0.18288)
		(layer "In6.Cu")
		(net "M_D_CPU0_SA_DQ<2>")
	)
	(segment
		(start 297.013884 -312.363612)
		(end 296.787824 -312.363612)
		(width 0.18288)
		(layer "In6.Cu")
		(net "M_D_CPU0_SA_DQ<2>")
	)
	(segment
		(start 288.524696 -315.135006)
		(end 286.01289 -317.646812)
		(width 0.18288)
		(layer "In6.Cu")
		(net "M_D_CPU0_SA_DQ<2>")
	)
	(segment
		(start 298.673774 -309.941722)
		(end 297.123358 -311.492138)
		(width 0.18288)
		(layer "In6.Cu")
		(net "M_D_CPU0_SA_DQ<2>")
	)
	(segment
		(start 313.45759 -303.141888)
		(end 312.607706 -303.991772)
		(width 0.18288)
		(layer "In6.Cu")
		(net "M_D_CPU0_SA_DQ<2>")
	)
	(segment
		(start 289.940746 -315.135006)
		(end 288.524696 -315.135006)
		(width 0.18288)
		(layer "In6.Cu")
		(net "M_D_CPU0_SA_DQ<2>")
	)
	(segment
		(start 315.137546 -301.729394)
		(end 315.137546 -302.494442)
		(width 0.18288)
		(layer "In6.Cu")
		(net "M_D_CPU0_SA_DQ<2>")
	)
	(segment
		(start 317.744348 -297.018202)
		(end 317.744348 -299.122592)
		(width 0.18288)
		(layer "In6.Cu")
		(net "M_D_CPU0_SA_DQ<2>")
	)
	(segment
		(start 332.049882 -282.87599)
		(end 331.88656 -282.87599)
		(width 0.18288)
		(layer "In6.Cu")
		(net "M_D_CPU0_SA_DQ<2>")
	)
	(segment
		(start 333.280512 -282.406344)
		(end 333.280512 -282.438094)
		(width 0.088646)
		(layer "In6.Cu")
		(net "M_D_CPU0_SA_DQ<2>")
	)
	(segment
		(start 304.684938 -307.363368)
		(end 301.995586 -308.47792)
		(width 0.18288)
		(layer "In6.Cu")
		(net "M_D_CPU0_SA_DQ<2>")
	)
	(segment
		(start 272.8468 -316.063884)
		(end 271.742408 -316.063884)
		(width 0.18288)
		(layer "In6.Cu")
		(net "M_D_CPU0_SA_DQ<2>")
	)
	(segment
		(start 343.996264 -276.219158)
		(end 343.981532 -276.210522)
		(width 0.088646)
		(layer "In6.Cu")
		(net "M_D_CPU0_SA_DQ<2>")
	)
	(segment
		(start 306.264564 -305.783742)
		(end 304.684938 -307.363368)
		(width 0.18288)
		(layer "In6.Cu")
		(net "M_D_CPU0_SA_DQ<2>")
	)
	(segment
		(start 271.559528 -315.722508)
		(end 271.376648 -315.539628)
		(width 0.18288)
		(layer "In6.Cu")
		(net "M_D_CPU0_SA_DQ<2>")
	)
	(segment
		(start 286.01289 -317.646812)
		(end 282.80868 -317.646812)
		(width 0.18288)
		(layer "In6.Cu")
		(net "M_D_CPU0_SA_DQ<2>")
	)
	(segment
		(start 306.74183 -305.783742)
		(end 306.264564 -305.783742)
		(width 0.18288)
		(layer "In6.Cu")
		(net "M_D_CPU0_SA_DQ<2>")
	)
	(segment
		(start 343.148666 -276.693122)
		(end 343.148666 -276.708616)
		(width 0.088646)
		(layer "In6.Cu")
		(net "M_D_CPU0_SA_DQ<2>")
	)
	(segment
		(start 315.137546 -302.494442)
		(end 314.4901 -303.141888)
		(width 0.18288)
		(layer "In6.Cu")
		(net "M_D_CPU0_SA_DQ<2>")
	)
	(segment
		(start 344.653616 -276.708616)
		(end 344.340942 -276.708616)
		(width 0.088646)
		(layer "In6.Cu")
		(net "M_D_CPU0_SA_DQ<2>")
	)
	(segment
		(start 292.476936 -313.34202)
		(end 291.828728 -313.990228)
		(width 0.18288)
		(layer "In6.Cu")
		(net "M_D_CPU0_SA_DQ<2>")
	)
	(segment
		(start 293.42588 -313.182)
		(end 293.26586 -313.34202)
		(width 0.18288)
		(layer "In6.Cu")
		(net "M_D_CPU0_SA_DQ<2>")
	)
	(segment
		(start 312.607706 -303.991772)
		(end 308.825646 -303.991772)
		(width 0.18288)
		(layer "In6.Cu")
		(net "M_D_CPU0_SA_DQ<2>")
	)
	(segment
		(start 271.742408 -316.063884)
		(end 271.559528 -315.881004)
		(width 0.18288)
		(layer "In6.Cu")
		(net "M_D_CPU0_SA_DQ<2>")
	)
	(segment
		(start 307.616352 -304.90922)
		(end 306.74183 -305.783742)
		(width 0.18288)
		(layer "In6.Cu")
		(net "M_D_CPU0_SA_DQ<2>")
	)
	(segment
		(start 297.278298 -312.099198)
		(end 297.013884 -312.363612)
		(width 0.18288)
		(layer "In6.Cu")
		(net "M_D_CPU0_SA_DQ<2>")
	)
	(segment
		(start 271.051528 -315.539628)
		(end 270.868648 -315.722508)
		(width 0.18288)
		(layer "In6.Cu")
		(net "M_D_CPU0_SA_DQ<2>")
	)
	(segment
		(start 293.26586 -313.34202)
		(end 292.476936 -313.34202)
		(width 0.18288)
		(layer "In6.Cu")
		(net "M_D_CPU0_SA_DQ<2>")
	)
	(segment
		(start 291.085524 -313.990228)
		(end 289.940746 -315.135006)
		(width 0.18288)
		(layer "In6.Cu")
		(net "M_D_CPU0_SA_DQ<2>")
	)
	(segment
		(start 296.37482 -312.176668)
		(end 295.209468 -313.34202)
		(width 0.18288)
		(layer "In6.Cu")
		(net "M_D_CPU0_SA_DQ<2>")
	)
	(segment
		(start 296.60088 -312.176668)
		(end 296.37482 -312.176668)
		(width 0.18288)
		(layer "In6.Cu")
		(net "M_D_CPU0_SA_DQ<2>")
	)
	(segment
		(start 344.00236 -276.222714)
		(end 343.996264 -276.219158)
		(width 0.088646)
		(layer "In6.Cu")
		(net "M_D_CPU0_SA_DQ<2>")
	)
	(segment
		(start 297.278298 -311.873138)
		(end 297.278298 -312.099198)
		(width 0.18288)
		(layer "In6.Cu")
		(net "M_D_CPU0_SA_DQ<2>")
	)
	(segment
		(start 308.825646 -303.991772)
		(end 307.908198 -304.90922)
		(width 0.18288)
		(layer "In6.Cu")
		(net "M_D_CPU0_SA_DQ<2>")
	)
	(segment
		(start 273.22399 -315.686694)
		(end 272.8468 -316.063884)
		(width 0.18288)
		(layer "In6.Cu")
		(net "M_D_CPU0_SA_DQ<2>")
	)
	(segment
		(start 337.80095 -279.469596)
		(end 337.79206 -279.474676)
		(width 0.088646)
		(layer "In6.Cu")
		(net "M_D_CPU0_SA_DQ<2>")
	)
	(segment
		(start 334.04175 -281.097482)
		(end 334.03286 -281.102562)
		(width 0.088646)
		(layer "In6.Cu")
		(net "M_D_CPU0_SA_DQ<2>")
	)
	(segment
		(start 334.220312 -280.759662)
		(end 334.220312 -280.778204)
		(width 0.088646)
		(layer "In6.Cu")
		(net "M_D_CPU0_SA_DQ<2>")
	)
	(segment
		(start 307.908198 -304.90922)
		(end 307.616352 -304.90922)
		(width 0.18288)
		(layer "In6.Cu")
		(net "M_D_CPU0_SA_DQ<2>")
	)
	(segment
		(start 338.27085 -278.65578)
		(end 338.26196 -278.66086)
		(width 0.088646)
		(layer "In6.Cu")
		(net "M_D_CPU0_SA_DQ<2>")
	)
	(segment
		(start 338.919312 -277.512526)
		(end 338.919312 -277.531068)
		(width 0.088646)
		(layer "In6.Cu")
		(net "M_D_CPU0_SA_DQ<2>")
	)
	(segment
		(start 332.842616 -282.87599)
		(end 332.049882 -282.87599)
		(width 0.088646)
		(layer "In6.Cu")
		(net "M_D_CPU0_SA_DQ<2>")
	)
	(segment
		(start 294.27932 -313.34202)
		(end 294.1193 -313.182)
		(width 0.18288)
		(layer "In6.Cu")
		(net "M_D_CPU0_SA_DQ<2>")
	)
	(segment
		(start 297.123358 -311.718198)
		(end 297.278298 -311.873138)
		(width 0.18288)
		(layer "In6.Cu")
		(net "M_D_CPU0_SA_DQ<2>")
	)
	(segment
		(start 334.690212 -279.954228)
		(end 334.690212 -279.964134)
		(width 0.088646)
		(layer "In6.Cu")
		(net "M_D_CPU0_SA_DQ<2>")
	)
	(segment
		(start 269.426436 -316.063884)
		(end 268.829282 -315.46673)
		(width 0.18288)
		(layer "In6.Cu")
		(net "M_D_CPU0_SA_DQ<2>")
	)
	(segment
		(start 274.636992 -315.686694)
		(end 273.22399 -315.686694)
		(width 0.18288)
		(layer "In6.Cu")
		(net "M_D_CPU0_SA_DQ<2>")
	)
	(segment
		(start 339.212174 -277.026878)
		(end 339.20176 -277.032974)
		(width 0.088646)
		(layer "In6.Cu")
		(net "M_D_CPU0_SA_DQ<2>")
	)
	(segment
		(start 296.787824 -312.363612)
		(end 296.60088 -312.176668)
		(width 0.18288)
		(layer "In6.Cu")
		(net "M_D_CPU0_SA_DQ<2>")
	)
	(segment
		(start 331.88656 -282.87599)
		(end 317.744348 -297.018202)
		(width 0.18288)
		(layer "In6.Cu")
		(net "M_D_CPU0_SA_DQ<2>")
	)
	(segment
		(start 294.1193 -313.182)
		(end 294.1193 -312.895742)
		(width 0.18288)
		(layer "In6.Cu")
		(net "M_D_CPU0_SA_DQ<2>")
	)
	(segment
		(start 293.42588 -312.895742)
		(end 293.42588 -313.182)
		(width 0.18288)
		(layer "In6.Cu")
		(net "M_D_CPU0_SA_DQ<2>")
	)
	(segment
		(start 333.280258 -282.396438)
		(end 333.280512 -282.406344)
		(width 0.088646)
		(layer "In6.Cu")
		(net "M_D_CPU0_SA_DQ<2>")
	)
	(segment
		(start 294.1193 -312.895742)
		(end 293.95928 -312.735722)
		(width 0.18288)
		(layer "In6.Cu")
		(net "M_D_CPU0_SA_DQ<2>")
	)
	(segment
		(start 337.979512 -279.140412)
		(end 337.979512 -279.150318)
		(width 0.088646)
		(layer "In6.Cu")
		(net "M_D_CPU0_SA_DQ<2>")
	)
	(segment
		(start 301.995586 -308.47792)
		(end 300.531784 -309.941722)
		(width 0.18288)
		(layer "In6.Cu")
		(net "M_D_CPU0_SA_DQ<2>")
	)
	(arc
		(start 334.220312 -280.778204)
		(mid 334.172633 -280.961104)
		(end 334.04175 -281.097482)
		(width 0.088646)
		(layer "In6.Cu")
		(net "M_D_CPU0_SA_DQ<2>")
	)
	(arc
		(start 339.767418 -277.032974)
		(mid 339.490605 -276.957104)
		(end 339.212174 -277.026878)
		(width 0.088646)
		(layer "In6.Cu")
		(net "M_D_CPU0_SA_DQ<2>")
	)
	(arc
		(start 334.03286 -281.102562)
		(mid 333.828525 -281.305167)
		(end 333.750412 -281.582114)
		(width 0.088646)
		(layer "In6.Cu")
		(net "M_D_CPU0_SA_DQ<2>")
	)
	(arc
		(start 340.707218 -277.032974)
		(mid 340.433019 -276.957139)
		(end 340.156546 -277.024338)
		(width 0.088646)
		(layer "In6.Cu")
		(net "M_D_CPU0_SA_DQ<2>")
	)
	(arc
		(start 338.732114 -277.84679)
		(mid 338.528633 -278.047594)
		(end 338.449412 -278.322278)
		(width 0.088646)
		(layer "In6.Cu")
		(net "M_D_CPU0_SA_DQ<2>")
	)
	(arc
		(start 338.919312 -277.531068)
		(mid 338.867042 -277.713433)
		(end 338.732114 -277.84679)
		(width 0.088646)
		(layer "In6.Cu")
		(net "M_D_CPU0_SA_DQ<2>")
	)
	(arc
		(start 339.20176 -277.032974)
		(mid 338.997425 -277.235579)
		(end 338.919312 -277.512526)
		(width 0.088646)
		(layer "In6.Cu")
		(net "M_D_CPU0_SA_DQ<2>")
	)
	(arc
		(start 338.26196 -278.66086)
		(mid 338.057625 -278.863465)
		(end 337.979512 -279.140412)
		(width 0.088646)
		(layer "In6.Cu")
		(net "M_D_CPU0_SA_DQ<2>")
	)
	(arc
		(start 342.586818 -277.032974)
		(mid 342.312619 -276.957139)
		(end 342.036146 -277.024338)
		(width 0.088646)
		(layer "In6.Cu")
		(net "M_D_CPU0_SA_DQ<2>")
	)
	(arc
		(start 336.477864 -279.474676)
		(mid 336.195162 -279.3989)
		(end 335.91246 -279.474676)
		(width 0.088646)
		(layer "In6.Cu")
		(net "M_D_CPU0_SA_DQ<2>")
	)
	(arc
		(start 344.275156 -276.64283)
		(mid 344.187868 -276.400874)
		(end 344.00236 -276.222714)
		(width 0.088646)
		(layer "In6.Cu")
		(net "M_D_CPU0_SA_DQ<2>")
	)
	(arc
		(start 342.961214 -277.032974)
		(mid 342.774016 -277.083117)
		(end 342.586818 -277.032974)
		(width 0.088646)
		(layer "In6.Cu")
		(net "M_D_CPU0_SA_DQ<2>")
	)
	(arc
		(start 336.85226 -279.474676)
		(mid 336.665062 -279.524819)
		(end 336.477864 -279.474676)
		(width 0.088646)
		(layer "In6.Cu")
		(net "M_D_CPU0_SA_DQ<2>")
	)
	(arc
		(start 337.79206 -279.474676)
		(mid 337.604862 -279.524819)
		(end 337.417664 -279.474676)
		(width 0.088646)
		(layer "In6.Cu")
		(net "M_D_CPU0_SA_DQ<2>")
	)
	(arc
		(start 334.690212 -279.964134)
		(mid 334.642533 -280.147034)
		(end 334.51165 -280.283412)
		(width 0.088646)
		(layer "In6.Cu")
		(net "M_D_CPU0_SA_DQ<2>")
	)
	(arc
		(start 333.56296 -281.916378)
		(mid 333.358315 -282.119149)
		(end 333.280258 -282.396438)
		(width 0.088646)
		(layer "In6.Cu")
		(net "M_D_CPU0_SA_DQ<2>")
	)
	(arc
		(start 343.981532 -276.210522)
		(mid 343.705057 -276.143202)
		(end 343.43086 -276.219158)
		(width 0.088646)
		(layer "In6.Cu")
		(net "M_D_CPU0_SA_DQ<2>")
	)
	(arc
		(start 335.91246 -279.474676)
		(mid 335.725262 -279.524819)
		(end 335.538064 -279.474676)
		(width 0.088646)
		(layer "In6.Cu")
		(net "M_D_CPU0_SA_DQ<2>")
	)
	(arc
		(start 341.081614 -277.032974)
		(mid 340.894416 -277.083117)
		(end 340.707218 -277.032974)
		(width 0.088646)
		(layer "In6.Cu")
		(net "M_D_CPU0_SA_DQ<2>")
	)
	(arc
		(start 334.50276 -280.288492)
		(mid 334.300474 -280.487473)
		(end 334.220312 -280.759662)
		(width 0.088646)
		(layer "In6.Cu")
		(net "M_D_CPU0_SA_DQ<2>")
	)
	(arc
		(start 340.141814 -277.032974)
		(mid 339.954616 -277.083117)
		(end 339.767418 -277.032974)
		(width 0.088646)
		(layer "In6.Cu")
		(net "M_D_CPU0_SA_DQ<2>")
	)
	(arc
		(start 343.148666 -276.708616)
		(mid 343.100987 -276.891516)
		(end 342.970104 -277.027894)
		(width 0.088646)
		(layer "In6.Cu")
		(net "M_D_CPU0_SA_DQ<2>")
	)
	(arc
		(start 342.021414 -277.032974)
		(mid 341.834216 -277.083117)
		(end 341.647018 -277.032974)
		(width 0.088646)
		(layer "In6.Cu")
		(net "M_D_CPU0_SA_DQ<2>")
	)
	(arc
		(start 338.449412 -278.336502)
		(mid 338.401733 -278.519402)
		(end 338.27085 -278.65578)
		(width 0.088646)
		(layer "In6.Cu")
		(net "M_D_CPU0_SA_DQ<2>")
	)
	(arc
		(start 334.97266 -279.474676)
		(mid 334.768325 -279.677281)
		(end 334.690212 -279.954228)
		(width 0.088646)
		(layer "In6.Cu")
		(net "M_D_CPU0_SA_DQ<2>")
	)
	(arc
		(start 335.538064 -279.474676)
		(mid 335.255362 -279.3989)
		(end 334.97266 -279.474676)
		(width 0.088646)
		(layer "In6.Cu")
		(net "M_D_CPU0_SA_DQ<2>")
	)
	(arc
		(start 337.979512 -279.150318)
		(mid 337.931833 -279.333218)
		(end 337.80095 -279.469596)
		(width 0.088646)
		(layer "In6.Cu")
		(net "M_D_CPU0_SA_DQ<2>")
	)
	(arc
		(start 337.417664 -279.474676)
		(mid 337.134962 -279.3989)
		(end 336.85226 -279.474676)
		(width 0.088646)
		(layer "In6.Cu")
		(net "M_D_CPU0_SA_DQ<2>")
	)
	(arc
		(start 341.647018 -277.032974)
		(mid 341.372819 -276.957139)
		(end 341.096346 -277.024338)
		(width 0.088646)
		(layer "In6.Cu")
		(net "M_D_CPU0_SA_DQ<2>")
	)
	(arc
		(start 333.750412 -281.59202)
		(mid 333.702733 -281.77492)
		(end 333.57185 -281.911298)
		(width 0.088646)
		(layer "In6.Cu")
		(net "M_D_CPU0_SA_DQ<2>")
	)
	(arc
		(start 343.43086 -276.219158)
		(mid 343.228037 -276.419389)
		(end 343.148666 -276.693122)
		(width 0.088646)
		(layer "In6.Cu")
		(net "M_D_CPU0_SA_DQ<2>")
	)
	(segment
		(start 257.626104 -280.827988)
		(end 257.414776 -280.61666)
		(width 0.20066)
		(layer "F.Cu")
		(net "M_D_CPU0_SA_DQ<29>")
	)
	(segment
		(start 264.729214 -280.61666)
		(end 263.624314 -280.61666)
		(width 0.20066)
		(layer "F.Cu")
		(net "M_D_CPU0_SA_DQ<29>")
	)
	(segment
		(start 347.002862 -265.592306)
		(end 347.002862 -266.128246)
		(width 0.20066)
		(layer "F.Cu")
		(net "M_D_CPU0_SA_DQ<29>")
	)
	(segment
		(start 261.984998 -280.61666)
		(end 261.560056 -280.191718)
		(width 0.20066)
		(layer "F.Cu")
		(net "M_D_CPU0_SA_DQ<29>")
	)
	(segment
		(start 258.28498 -280.345388)
		(end 258.28498 -280.673556)
		(width 0.20066)
		(layer "F.Cu")
		(net "M_D_CPU0_SA_DQ<29>")
	)
	(segment
		(start 259.065268 -280.191718)
		(end 259.056378 -280.182828)
		(width 0.1016)
		(layer "F.Cu")
		(net "M_D_CPU0_SA_DQ<29>")
	)
	(segment
		(start 259.056378 -280.182828)
		(end 258.44754 -280.182828)
		(width 0.20066)
		(layer "F.Cu")
		(net "M_D_CPU0_SA_DQ<29>")
	)
	(segment
		(start 258.28498 -280.673556)
		(end 258.130548 -280.827988)
		(width 0.20066)
		(layer "F.Cu")
		(net "M_D_CPU0_SA_DQ<29>")
	)
	(segment
		(start 258.130548 -280.827988)
		(end 257.626104 -280.827988)
		(width 0.20066)
		(layer "F.Cu")
		(net "M_D_CPU0_SA_DQ<29>")
	)
	(segment
		(start 261.050786 -280.191718)
		(end 259.065268 -280.191718)
		(width 0.1016)
		(layer "F.Cu")
		(net "M_D_CPU0_SA_DQ<29>")
	)
	(segment
		(start 263.624314 -280.61666)
		(end 261.984998 -280.61666)
		(width 0.20066)
		(layer "F.Cu")
		(net "M_D_CPU0_SA_DQ<29>")
	)
	(segment
		(start 261.381494 -280.191718)
		(end 261.050786 -280.191718)
		(width 0.101854)
		(layer "F.Cu")
		(net "M_D_CPU0_SA_DQ<29>")
	)
	(segment
		(start 258.44754 -280.182828)
		(end 258.28498 -280.345388)
		(width 0.20066)
		(layer "F.Cu")
		(net "M_D_CPU0_SA_DQ<29>")
	)
	(segment
		(start 261.560056 -280.191718)
		(end 261.381494 -280.191718)
		(width 0.20066)
		(layer "F.Cu")
		(net "M_D_CPU0_SA_DQ<29>")
	)
	(segment
		(start 347.003116 -265.592306)
		(end 347.002862 -265.592306)
		(width 0.20066)
		(layer "F.Cu")
		(net "M_D_CPU0_SA_DQ<29>")
	)
	(segment
		(start 257.414776 -280.61666)
		(end 256.080514 -280.61666)
		(width 0.20066)
		(layer "F.Cu")
		(net "M_D_CPU0_SA_DQ<29>")
	)
	(segment
		(start 271.819116 -280.885646)
		(end 271.626076 -281.078686)
		(width 0.18288)
		(layer "In11.Cu")
		(net "M_D_CPU0_SA_DQ<29>")
	)
	(segment
		(start 266.27582 -281.60726)
		(end 266.27582 -281.322272)
		(width 0.18288)
		(layer "In11.Cu")
		(net "M_D_CPU0_SA_DQ<29>")
	)
	(segment
		(start 278.62911 -280.19248)
		(end 278.476964 -280.344626)
		(width 0.18288)
		(layer "In11.Cu")
		(net "M_D_CPU0_SA_DQ<29>")
	)
	(segment
		(start 336.477864 -265.803634)
		(end 336.477864 -265.803888)
		(width 0.088646)
		(layer "In11.Cu")
		(net "M_D_CPU0_SA_DQ<29>")
	)
	(segment
		(start 265.057128 -280.61666)
		(end 264.729214 -280.61666)
		(width 0.18288)
		(layer "In11.Cu")
		(net "M_D_CPU0_SA_DQ<29>")
	)
	(segment
		(start 341.176864 -265.803634)
		(end 341.162132 -265.81227)
		(width 0.088646)
		(layer "In11.Cu")
		(net "M_D_CPU0_SA_DQ<29>")
	)
	(segment
		(start 307.228494 -278.541226)
		(end 307.025294 -278.338026)
		(width 0.18288)
		(layer "In11.Cu")
		(net "M_D_CPU0_SA_DQ<29>")
	)
	(segment
		(start 291.810694 -279.963626)
		(end 291.175694 -279.963626)
		(width 0.18288)
		(layer "In11.Cu")
		(net "M_D_CPU0_SA_DQ<29>")
	)
	(segment
		(start 292.255194 -280.408126)
		(end 291.810694 -279.963626)
		(width 0.18288)
		(layer "In11.Cu")
		(net "M_D_CPU0_SA_DQ<29>")
	)
	(segment
		(start 347.19895 -265.808714)
		(end 347.19006 -265.803634)
		(width 0.088646)
		(layer "In11.Cu")
		(net "M_D_CPU0_SA_DQ<29>")
	)
	(segment
		(start 308.393084 -277.709376)
		(end 308.393084 -278.088852)
		(width 0.18288)
		(layer "In11.Cu")
		(net "M_D_CPU0_SA_DQ<29>")
	)
	(segment
		(start 347.002862 -266.128246)
		(end 347.003116 -266.127992)
		(width 0.088646)
		(layer "In11.Cu")
		(net "M_D_CPU0_SA_DQ<29>")
	)
	(segment
		(start 331.95133 -265.87958)
		(end 331.355446 -266.475464)
		(width 0.088646)
		(layer "In11.Cu")
		(net "M_D_CPU0_SA_DQ<29>")
	)
	(segment
		(start 267.791692 -281.042364)
		(end 267.704824 -281.129232)
		(width 0.18288)
		(layer "In11.Cu")
		(net "M_D_CPU0_SA_DQ<29>")
	)
	(segment
		(start 311.698132 -276.769322)
		(end 310.931814 -277.53564)
		(width 0.18288)
		(layer "In11.Cu")
		(net "M_D_CPU0_SA_DQ<29>")
	)
	(segment
		(start 347.315536 -266.127992)
		(end 347.37294 -266.070588)
		(width 0.088646)
		(layer "In11.Cu")
		(net "M_D_CPU0_SA_DQ<29>")
	)
	(segment
		(start 313.540394 -276.769322)
		(end 313.347354 -276.962362)
		(width 0.18288)
		(layer "In11.Cu")
		(net "M_D_CPU0_SA_DQ<29>")
	)
	(segment
		(start 267.1699 -281.129232)
		(end 266.97686 -281.322272)
		(width 0.18288)
		(layer "In11.Cu")
		(net "M_D_CPU0_SA_DQ<29>")
	)
	(segment
		(start 282.642818 -280.120598)
		(end 280.467308 -280.120598)
		(width 0.18288)
		(layer "In11.Cu")
		(net "M_D_CPU0_SA_DQ<29>")
	)
	(segment
		(start 271.626076 -281.078686)
		(end 271.626076 -281.338274)
		(width 0.18288)
		(layer "In11.Cu")
		(net "M_D_CPU0_SA_DQ<29>")
	)
	(segment
		(start 266.46886 -281.8003)
		(end 266.27582 -281.60726)
		(width 0.18288)
		(layer "In11.Cu")
		(net "M_D_CPU0_SA_DQ<29>")
	)
	(segment
		(start 271.433036 -281.531314)
		(end 271.118076 -281.531314)
		(width 0.18288)
		(layer "In11.Cu")
		(net "M_D_CPU0_SA_DQ<29>")
	)
	(segment
		(start 269.628874 -280.885646)
		(end 269.472156 -281.042364)
		(width 0.18288)
		(layer "In11.Cu")
		(net "M_D_CPU0_SA_DQ<29>")
	)
	(segment
		(start 310.931814 -277.53564)
		(end 308.56682 -277.53564)
		(width 0.18288)
		(layer "In11.Cu")
		(net "M_D_CPU0_SA_DQ<29>")
	)
	(segment
		(start 297.841924 -279.342596)
		(end 297.271694 -279.912826)
		(width 0.18288)
		(layer "In11.Cu")
		(net "M_D_CPU0_SA_DQ<29>")
	)
	(segment
		(start 331.355446 -266.475464)
		(end 331.355446 -267.048234)
		(width 0.088646)
		(layer "In11.Cu")
		(net "M_D_CPU0_SA_DQ<29>")
	)
	(segment
		(start 270.925036 -281.078686)
		(end 270.731996 -280.885646)
		(width 0.18288)
		(layer "In11.Cu")
		(net "M_D_CPU0_SA_DQ<29>")
	)
	(segment
		(start 277.408894 -280.344626)
		(end 277.205694 -280.141426)
		(width 0.18288)
		(layer "In11.Cu")
		(net "M_D_CPU0_SA_DQ<29>")
	)
	(segment
		(start 299.887894 -279.176226)
		(end 299.721524 -279.342596)
		(width 0.18288)
		(layer "In11.Cu")
		(net "M_D_CPU0_SA_DQ<29>")
	)
	(segment
		(start 277.205694 -280.141426)
		(end 273.802094 -280.141426)
		(width 0.18288)
		(layer "In11.Cu")
		(net "M_D_CPU0_SA_DQ<29>")
	)
	(segment
		(start 345.875864 -265.803634)
		(end 345.861132 -265.81227)
		(width 0.088646)
		(layer "In11.Cu")
		(net "M_D_CPU0_SA_DQ<29>")
	)
	(segment
		(start 280.467308 -280.120598)
		(end 280.395426 -280.19248)
		(width 0.18288)
		(layer "In11.Cu")
		(net "M_D_CPU0_SA_DQ<29>")
	)
	(segment
		(start 313.347354 -276.962362)
		(end 313.347354 -277.213822)
		(width 0.18288)
		(layer "In11.Cu")
		(net "M_D_CPU0_SA_DQ<29>")
	)
	(segment
		(start 308.393084 -278.088852)
		(end 307.94071 -278.541226)
		(width 0.18288)
		(layer "In11.Cu")
		(net "M_D_CPU0_SA_DQ<29>")
	)
	(segment
		(start 266.08278 -281.129232)
		(end 265.5697 -281.129232)
		(width 0.18288)
		(layer "In11.Cu")
		(net "M_D_CPU0_SA_DQ<29>")
	)
	(segment
		(start 307.025294 -278.338026)
		(end 303.977294 -278.338026)
		(width 0.18288)
		(layer "In11.Cu")
		(net "M_D_CPU0_SA_DQ<29>")
	)
	(segment
		(start 288.127694 -279.506426)
		(end 287.848294 -279.227026)
		(width 0.18288)
		(layer "In11.Cu")
		(net "M_D_CPU0_SA_DQ<29>")
	)
	(segment
		(start 312.646314 -277.213822)
		(end 312.646314 -276.962362)
		(width 0.18288)
		(layer "In11.Cu")
		(net "M_D_CPU0_SA_DQ<29>")
	)
	(segment
		(start 267.704824 -281.129232)
		(end 267.1699 -281.129232)
		(width 0.18288)
		(layer "In11.Cu")
		(net "M_D_CPU0_SA_DQ<29>")
	)
	(segment
		(start 303.139094 -279.176226)
		(end 299.887894 -279.176226)
		(width 0.18288)
		(layer "In11.Cu")
		(net "M_D_CPU0_SA_DQ<29>")
	)
	(segment
		(start 269.472156 -281.042364)
		(end 267.791692 -281.042364)
		(width 0.18288)
		(layer "In11.Cu")
		(net "M_D_CPU0_SA_DQ<29>")
	)
	(segment
		(start 289.702494 -279.506426)
		(end 288.127694 -279.506426)
		(width 0.18288)
		(layer "In11.Cu")
		(net "M_D_CPU0_SA_DQ<29>")
	)
	(segment
		(start 265.5697 -281.129232)
		(end 265.057128 -280.61666)
		(width 0.18288)
		(layer "In11.Cu")
		(net "M_D_CPU0_SA_DQ<29>")
	)
	(segment
		(start 315.39434 -276.769322)
		(end 313.540394 -276.769322)
		(width 0.18288)
		(layer "In11.Cu")
		(net "M_D_CPU0_SA_DQ<29>")
	)
	(segment
		(start 270.731996 -280.885646)
		(end 269.628874 -280.885646)
		(width 0.18288)
		(layer "In11.Cu")
		(net "M_D_CPU0_SA_DQ<29>")
	)
	(segment
		(start 307.94071 -278.541226)
		(end 307.228494 -278.541226)
		(width 0.18288)
		(layer "In11.Cu")
		(net "M_D_CPU0_SA_DQ<29>")
	)
	(segment
		(start 308.56682 -277.53564)
		(end 308.393084 -277.709376)
		(width 0.18288)
		(layer "In11.Cu")
		(net "M_D_CPU0_SA_DQ<29>")
	)
	(segment
		(start 266.97686 -281.322272)
		(end 266.97686 -281.60726)
		(width 0.18288)
		(layer "In11.Cu")
		(net "M_D_CPU0_SA_DQ<29>")
	)
	(segment
		(start 343.996264 -265.803634)
		(end 343.981532 -265.81227)
		(width 0.088646)
		(layer "In11.Cu")
		(net "M_D_CPU0_SA_DQ<29>")
	)
	(segment
		(start 271.626076 -281.338274)
		(end 271.433036 -281.531314)
		(width 0.18288)
		(layer "In11.Cu")
		(net "M_D_CPU0_SA_DQ<29>")
	)
	(segment
		(start 324.922388 -267.241274)
		(end 315.39434 -276.769322)
		(width 0.18288)
		(layer "In11.Cu")
		(net "M_D_CPU0_SA_DQ<29>")
	)
	(segment
		(start 293.71671 -280.19248)
		(end 293.501064 -280.408126)
		(width 0.18288)
		(layer "In11.Cu")
		(net "M_D_CPU0_SA_DQ<29>")
	)
	(segment
		(start 295.76268 -279.912826)
		(end 295.483026 -280.19248)
		(width 0.18288)
		(layer "In11.Cu")
		(net "M_D_CPU0_SA_DQ<29>")
	)
	(segment
		(start 331.162406 -267.241274)
		(end 330.903072 -267.241274)
		(width 0.088646)
		(layer "In11.Cu")
		(net "M_D_CPU0_SA_DQ<29>")
	)
	(segment
		(start 266.97686 -281.60726)
		(end 266.78382 -281.8003)
		(width 0.18288)
		(layer "In11.Cu")
		(net "M_D_CPU0_SA_DQ<29>")
	)
	(segment
		(start 293.501064 -280.408126)
		(end 292.255194 -280.408126)
		(width 0.18288)
		(layer "In11.Cu")
		(net "M_D_CPU0_SA_DQ<29>")
	)
	(segment
		(start 330.903072 -267.241274)
		(end 324.922388 -267.241274)
		(width 0.18288)
		(layer "In11.Cu")
		(net "M_D_CPU0_SA_DQ<29>")
	)
	(segment
		(start 291.175694 -279.963626)
		(end 290.972494 -280.166826)
		(width 0.18288)
		(layer "In11.Cu")
		(net "M_D_CPU0_SA_DQ<29>")
	)
	(segment
		(start 270.925036 -281.338274)
		(end 270.925036 -281.078686)
		(width 0.18288)
		(layer "In11.Cu")
		(net "M_D_CPU0_SA_DQ<29>")
	)
	(segment
		(start 266.78382 -281.8003)
		(end 266.46886 -281.8003)
		(width 0.18288)
		(layer "In11.Cu")
		(net "M_D_CPU0_SA_DQ<29>")
	)
	(segment
		(start 280.395426 -280.19248)
		(end 278.62911 -280.19248)
		(width 0.18288)
		(layer "In11.Cu")
		(net "M_D_CPU0_SA_DQ<29>")
	)
	(segment
		(start 303.977294 -278.338026)
		(end 303.139094 -279.176226)
		(width 0.18288)
		(layer "In11.Cu")
		(net "M_D_CPU0_SA_DQ<29>")
	)
	(segment
		(start 347.003116 -266.127992)
		(end 347.315536 -266.127992)
		(width 0.088646)
		(layer "In11.Cu")
		(net "M_D_CPU0_SA_DQ<29>")
	)
	(segment
		(start 299.721524 -279.342596)
		(end 297.841924 -279.342596)
		(width 0.18288)
		(layer "In11.Cu")
		(net "M_D_CPU0_SA_DQ<29>")
	)
	(segment
		(start 312.839354 -277.406862)
		(end 312.646314 -277.213822)
		(width 0.18288)
		(layer "In11.Cu")
		(net "M_D_CPU0_SA_DQ<29>")
	)
	(segment
		(start 343.056464 -265.803634)
		(end 343.041732 -265.81227)
		(width 0.088646)
		(layer "In11.Cu")
		(net "M_D_CPU0_SA_DQ<29>")
	)
	(segment
		(start 278.476964 -280.344626)
		(end 277.408894 -280.344626)
		(width 0.18288)
		(layer "In11.Cu")
		(net "M_D_CPU0_SA_DQ<29>")
	)
	(segment
		(start 290.362894 -280.166826)
		(end 289.702494 -279.506426)
		(width 0.18288)
		(layer "In11.Cu")
		(net "M_D_CPU0_SA_DQ<29>")
	)
	(segment
		(start 331.355446 -267.048234)
		(end 331.162406 -267.241274)
		(width 0.088646)
		(layer "In11.Cu")
		(net "M_D_CPU0_SA_DQ<29>")
	)
	(segment
		(start 273.802094 -280.141426)
		(end 273.057874 -280.885646)
		(width 0.18288)
		(layer "In11.Cu")
		(net "M_D_CPU0_SA_DQ<29>")
	)
	(segment
		(start 266.27582 -281.322272)
		(end 266.08278 -281.129232)
		(width 0.18288)
		(layer "In11.Cu")
		(net "M_D_CPU0_SA_DQ<29>")
	)
	(segment
		(start 295.483026 -280.19248)
		(end 293.71671 -280.19248)
		(width 0.18288)
		(layer "In11.Cu")
		(net "M_D_CPU0_SA_DQ<29>")
	)
	(segment
		(start 313.154314 -277.406862)
		(end 312.839354 -277.406862)
		(width 0.18288)
		(layer "In11.Cu")
		(net "M_D_CPU0_SA_DQ<29>")
	)
	(segment
		(start 271.118076 -281.531314)
		(end 270.925036 -281.338274)
		(width 0.18288)
		(layer "In11.Cu")
		(net "M_D_CPU0_SA_DQ<29>")
	)
	(segment
		(start 290.972494 -280.166826)
		(end 290.362894 -280.166826)
		(width 0.18288)
		(layer "In11.Cu")
		(net "M_D_CPU0_SA_DQ<29>")
	)
	(segment
		(start 273.057874 -280.885646)
		(end 271.819116 -280.885646)
		(width 0.18288)
		(layer "In11.Cu")
		(net "M_D_CPU0_SA_DQ<29>")
	)
	(segment
		(start 284.851094 -279.227026)
		(end 284.735524 -279.342596)
		(width 0.18288)
		(layer "In11.Cu")
		(net "M_D_CPU0_SA_DQ<29>")
	)
	(segment
		(start 283.42082 -279.342596)
		(end 282.642818 -280.120598)
		(width 0.18288)
		(layer "In11.Cu")
		(net "M_D_CPU0_SA_DQ<29>")
	)
	(segment
		(start 344.936064 -265.803634)
		(end 344.921332 -265.81227)
		(width 0.088646)
		(layer "In11.Cu")
		(net "M_D_CPU0_SA_DQ<29>")
	)
	(segment
		(start 332.435962 -265.87958)
		(end 331.95133 -265.87958)
		(width 0.088646)
		(layer "In11.Cu")
		(net "M_D_CPU0_SA_DQ<29>")
	)
	(segment
		(start 312.453274 -276.769322)
		(end 311.698132 -276.769322)
		(width 0.18288)
		(layer "In11.Cu")
		(net "M_D_CPU0_SA_DQ<29>")
	)
	(segment
		(start 287.848294 -279.227026)
		(end 284.851094 -279.227026)
		(width 0.18288)
		(layer "In11.Cu")
		(net "M_D_CPU0_SA_DQ<29>")
	)
	(segment
		(start 312.646314 -276.962362)
		(end 312.453274 -276.769322)
		(width 0.18288)
		(layer "In11.Cu")
		(net "M_D_CPU0_SA_DQ<29>")
	)
	(segment
		(start 339.297264 -265.803634)
		(end 339.282532 -265.81227)
		(width 0.088646)
		(layer "In11.Cu")
		(net "M_D_CPU0_SA_DQ<29>")
	)
	(segment
		(start 284.735524 -279.342596)
		(end 283.42082 -279.342596)
		(width 0.18288)
		(layer "In11.Cu")
		(net "M_D_CPU0_SA_DQ<29>")
	)
	(segment
		(start 297.271694 -279.912826)
		(end 295.76268 -279.912826)
		(width 0.18288)
		(layer "In11.Cu")
		(net "M_D_CPU0_SA_DQ<29>")
	)
	(segment
		(start 342.116664 -265.803634)
		(end 342.101932 -265.81227)
		(width 0.088646)
		(layer "In11.Cu")
		(net "M_D_CPU0_SA_DQ<29>")
	)
	(segment
		(start 313.347354 -277.213822)
		(end 313.154314 -277.406862)
		(width 0.18288)
		(layer "In11.Cu")
		(net "M_D_CPU0_SA_DQ<29>")
	)
	(arc
		(start 337.417664 -265.803634)
		(mid 337.134962 -265.87941)
		(end 336.85226 -265.803634)
		(width 0.088646)
		(layer "In11.Cu")
		(net "M_D_CPU0_SA_DQ<29>")
	)
	(arc
		(start 333.658464 -265.803888)
		(mid 333.375762 -265.87963)
		(end 333.09306 -265.803888)
		(width 0.088646)
		(layer "In11.Cu")
		(net "M_D_CPU0_SA_DQ<29>")
	)
	(arc
		(start 343.43086 -265.803634)
		(mid 343.243662 -265.753491)
		(end 343.056464 -265.803634)
		(width 0.088646)
		(layer "In11.Cu")
		(net "M_D_CPU0_SA_DQ<29>")
	)
	(arc
		(start 340.61146 -265.803634)
		(mid 340.424262 -265.753491)
		(end 340.237064 -265.803634)
		(width 0.088646)
		(layer "In11.Cu")
		(net "M_D_CPU0_SA_DQ<29>")
	)
	(arc
		(start 343.981532 -265.81227)
		(mid 343.705057 -265.87959)
		(end 343.43086 -265.803634)
		(width 0.088646)
		(layer "In11.Cu")
		(net "M_D_CPU0_SA_DQ<29>")
	)
	(arc
		(start 332.718664 -265.803888)
		(mid 332.582298 -265.860366)
		(end 332.435962 -265.87958)
		(width 0.088646)
		(layer "In11.Cu")
		(net "M_D_CPU0_SA_DQ<29>")
	)
	(arc
		(start 339.282532 -265.81227)
		(mid 339.006057 -265.87959)
		(end 338.73186 -265.803634)
		(width 0.088646)
		(layer "In11.Cu")
		(net "M_D_CPU0_SA_DQ<29>")
	)
	(arc
		(start 337.79206 -265.803634)
		(mid 337.604862 -265.753491)
		(end 337.417664 -265.803634)
		(width 0.088646)
		(layer "In11.Cu")
		(net "M_D_CPU0_SA_DQ<29>")
	)
	(arc
		(start 334.03286 -265.803888)
		(mid 333.845662 -265.753745)
		(end 333.658464 -265.803888)
		(width 0.088646)
		(layer "In11.Cu")
		(net "M_D_CPU0_SA_DQ<29>")
	)
	(arc
		(start 347.37294 -266.070588)
		(mid 347.314784 -265.920475)
		(end 347.19895 -265.808714)
		(width 0.088646)
		(layer "In11.Cu")
		(net "M_D_CPU0_SA_DQ<29>")
	)
	(arc
		(start 343.041732 -265.81227)
		(mid 342.765257 -265.87959)
		(end 342.49106 -265.803634)
		(width 0.088646)
		(layer "In11.Cu")
		(net "M_D_CPU0_SA_DQ<29>")
	)
	(arc
		(start 340.237064 -265.803634)
		(mid 339.954362 -265.87941)
		(end 339.67166 -265.803634)
		(width 0.088646)
		(layer "In11.Cu")
		(net "M_D_CPU0_SA_DQ<29>")
	)
	(arc
		(start 345.31046 -265.803634)
		(mid 345.123262 -265.753491)
		(end 344.936064 -265.803634)
		(width 0.088646)
		(layer "In11.Cu")
		(net "M_D_CPU0_SA_DQ<29>")
	)
	(arc
		(start 342.101932 -265.81227)
		(mid 341.825457 -265.87959)
		(end 341.55126 -265.803634)
		(width 0.088646)
		(layer "In11.Cu")
		(net "M_D_CPU0_SA_DQ<29>")
	)
	(arc
		(start 338.357464 -265.803634)
		(mid 338.074762 -265.87941)
		(end 337.79206 -265.803634)
		(width 0.088646)
		(layer "In11.Cu")
		(net "M_D_CPU0_SA_DQ<29>")
	)
	(arc
		(start 344.37066 -265.803634)
		(mid 344.183462 -265.753491)
		(end 343.996264 -265.803634)
		(width 0.088646)
		(layer "In11.Cu")
		(net "M_D_CPU0_SA_DQ<29>")
	)
	(arc
		(start 333.09306 -265.803888)
		(mid 332.905862 -265.753745)
		(end 332.718664 -265.803888)
		(width 0.088646)
		(layer "In11.Cu")
		(net "M_D_CPU0_SA_DQ<29>")
	)
	(arc
		(start 344.921332 -265.81227)
		(mid 344.644857 -265.87959)
		(end 344.37066 -265.803634)
		(width 0.088646)
		(layer "In11.Cu")
		(net "M_D_CPU0_SA_DQ<29>")
	)
	(arc
		(start 341.55126 -265.803634)
		(mid 341.364062 -265.753491)
		(end 341.176864 -265.803634)
		(width 0.088646)
		(layer "In11.Cu")
		(net "M_D_CPU0_SA_DQ<29>")
	)
	(arc
		(start 334.97266 -265.803888)
		(mid 334.785462 -265.753745)
		(end 334.598264 -265.803888)
		(width 0.088646)
		(layer "In11.Cu")
		(net "M_D_CPU0_SA_DQ<29>")
	)
	(arc
		(start 334.598264 -265.803888)
		(mid 334.315562 -265.87963)
		(end 334.03286 -265.803888)
		(width 0.088646)
		(layer "In11.Cu")
		(net "M_D_CPU0_SA_DQ<29>")
	)
	(arc
		(start 336.85226 -265.803634)
		(mid 336.665062 -265.753491)
		(end 336.477864 -265.803634)
		(width 0.088646)
		(layer "In11.Cu")
		(net "M_D_CPU0_SA_DQ<29>")
	)
	(arc
		(start 345.861132 -265.81227)
		(mid 345.584657 -265.87959)
		(end 345.31046 -265.803634)
		(width 0.088646)
		(layer "In11.Cu")
		(net "M_D_CPU0_SA_DQ<29>")
	)
	(arc
		(start 347.19006 -265.803634)
		(mid 347.002862 -265.753491)
		(end 346.815664 -265.803634)
		(width 0.088646)
		(layer "In11.Cu")
		(net "M_D_CPU0_SA_DQ<29>")
	)
	(arc
		(start 346.25026 -265.803634)
		(mid 346.063062 -265.753491)
		(end 345.875864 -265.803634)
		(width 0.088646)
		(layer "In11.Cu")
		(net "M_D_CPU0_SA_DQ<29>")
	)
	(arc
		(start 338.73186 -265.803634)
		(mid 338.544662 -265.753491)
		(end 338.357464 -265.803634)
		(width 0.088646)
		(layer "In11.Cu")
		(net "M_D_CPU0_SA_DQ<29>")
	)
	(arc
		(start 339.67166 -265.803634)
		(mid 339.484462 -265.753491)
		(end 339.297264 -265.803634)
		(width 0.088646)
		(layer "In11.Cu")
		(net "M_D_CPU0_SA_DQ<29>")
	)
	(arc
		(start 335.538064 -265.803888)
		(mid 335.255362 -265.87963)
		(end 334.97266 -265.803888)
		(width 0.088646)
		(layer "In11.Cu")
		(net "M_D_CPU0_SA_DQ<29>")
	)
	(arc
		(start 335.91246 -265.803888)
		(mid 335.725262 -265.753745)
		(end 335.538064 -265.803888)
		(width 0.088646)
		(layer "In11.Cu")
		(net "M_D_CPU0_SA_DQ<29>")
	)
	(arc
		(start 341.162132 -265.81227)
		(mid 340.885657 -265.87959)
		(end 340.61146 -265.803634)
		(width 0.088646)
		(layer "In11.Cu")
		(net "M_D_CPU0_SA_DQ<29>")
	)
	(arc
		(start 346.815664 -265.803634)
		(mid 346.532962 -265.87941)
		(end 346.25026 -265.803634)
		(width 0.088646)
		(layer "In11.Cu")
		(net "M_D_CPU0_SA_DQ<29>")
	)
	(arc
		(start 336.477864 -265.803888)
		(mid 336.195162 -265.87963)
		(end 335.91246 -265.803888)
		(width 0.088646)
		(layer "In11.Cu")
		(net "M_D_CPU0_SA_DQ<29>")
	)
	(arc
		(start 342.49106 -265.803634)
		(mid 342.303862 -265.753491)
		(end 342.116664 -265.803634)
		(width 0.088646)
		(layer "In11.Cu")
		(net "M_D_CPU0_SA_DQ<29>")
	)
	(segment
		(start 261.830312 -281.89174)
		(end 261.381494 -281.89174)
		(width 0.20066)
		(layer "F.Cu")
		(net "M_D_CPU0_SA_DQ<28>")
	)
	(segment
		(start 258.11226 -282.555442)
		(end 257.653536 -282.555442)
		(width 0.20066)
		(layer "F.Cu")
		(net "M_D_CPU0_SA_DQ<28>")
	)
	(segment
		(start 258.28498 -282.093162)
		(end 258.28498 -282.382722)
		(width 0.20066)
		(layer "F.Cu")
		(net "M_D_CPU0_SA_DQ<28>")
	)
	(segment
		(start 257.414776 -282.316682)
		(end 256.080514 -282.316682)
		(width 0.20066)
		(layer "F.Cu")
		(net "M_D_CPU0_SA_DQ<28>")
	)
	(segment
		(start 263.624314 -282.316682)
		(end 262.255254 -282.316682)
		(width 0.20066)
		(layer "F.Cu")
		(net "M_D_CPU0_SA_DQ<28>")
	)
	(segment
		(start 264.729214 -282.316682)
		(end 263.624314 -282.316682)
		(width 0.20066)
		(layer "F.Cu")
		(net "M_D_CPU0_SA_DQ<28>")
	)
	(segment
		(start 259.31241 -281.89174)
		(end 259.064506 -281.89174)
		(width 0.101854)
		(layer "F.Cu")
		(net "M_D_CPU0_SA_DQ<28>")
	)
	(segment
		(start 259.064506 -281.89174)
		(end 259.056378 -281.883612)
		(width 0.101854)
		(layer "F.Cu")
		(net "M_D_CPU0_SA_DQ<28>")
	)
	(segment
		(start 259.056378 -281.883612)
		(end 258.49453 -281.883612)
		(width 0.20066)
		(layer "F.Cu")
		(net "M_D_CPU0_SA_DQ<28>")
	)
	(segment
		(start 258.49453 -281.883612)
		(end 258.28498 -282.093162)
		(width 0.20066)
		(layer "F.Cu")
		(net "M_D_CPU0_SA_DQ<28>")
	)
	(segment
		(start 262.255254 -282.316682)
		(end 261.830312 -281.89174)
		(width 0.20066)
		(layer "F.Cu")
		(net "M_D_CPU0_SA_DQ<28>")
	)
	(segment
		(start 257.653536 -282.555442)
		(end 257.414776 -282.316682)
		(width 0.20066)
		(layer "F.Cu")
		(net "M_D_CPU0_SA_DQ<28>")
	)
	(segment
		(start 261.381494 -281.89174)
		(end 259.31241 -281.89174)
		(width 0.1016)
		(layer "F.Cu")
		(net "M_D_CPU0_SA_DQ<28>")
	)
	(segment
		(start 258.28498 -282.382722)
		(end 258.11226 -282.555442)
		(width 0.20066)
		(layer "F.Cu")
		(net "M_D_CPU0_SA_DQ<28>")
	)
	(arc
		(start 346.532962 -266.405868)
		(mid 346.533025 -266.673838)
		(end 346.533216 -266.941808)
		(width 0.20066)
		(layer "F.Cu")
		(net "M_D_CPU0_SA_DQ<28>")
	)
	(segment
		(start 330.903072 -268.257274)
		(end 325.343774 -268.257274)
		(width 0.18288)
		(layer "In11.Cu")
		(net "M_D_CPU0_SA_DQ<28>")
	)
	(segment
		(start 295.871138 -281.635454)
		(end 295.61409 -281.892502)
		(width 0.18288)
		(layer "In11.Cu")
		(net "M_D_CPU0_SA_DQ<28>")
	)
	(segment
		(start 310.79694 -279.292812)
		(end 308.91226 -279.292812)
		(width 0.18288)
		(layer "In11.Cu")
		(net "M_D_CPU0_SA_DQ<28>")
	)
	(segment
		(start 277.104094 -281.843226)
		(end 273.598894 -281.843226)
		(width 0.18288)
		(layer "In11.Cu")
		(net "M_D_CPU0_SA_DQ<28>")
	)
	(segment
		(start 312.862214 -278.605996)
		(end 312.702194 -278.445976)
		(width 0.18288)
		(layer "In11.Cu")
		(net "M_D_CPU0_SA_DQ<28>")
	)
	(segment
		(start 331.404468 -267.661136)
		(end 331.404468 -268.064234)
		(width 0.088646)
		(layer "In11.Cu")
		(net "M_D_CPU0_SA_DQ<28>")
	)
	(segment
		(start 313.555634 -278.605996)
		(end 312.862214 -278.605996)
		(width 0.18288)
		(layer "In11.Cu")
		(net "M_D_CPU0_SA_DQ<28>")
	)
	(segment
		(start 308.91226 -279.292812)
		(end 308.009544 -280.195528)
		(width 0.18288)
		(layer "In11.Cu")
		(net "M_D_CPU0_SA_DQ<28>")
	)
	(segment
		(start 305.651916 -280.815542)
		(end 305.336956 -280.815542)
		(width 0.18288)
		(layer "In11.Cu")
		(net "M_D_CPU0_SA_DQ<28>")
	)
	(segment
		(start 283.402278 -281.042618)
		(end 282.636468 -281.808428)
		(width 0.18288)
		(layer "In11.Cu")
		(net "M_D_CPU0_SA_DQ<28>")
	)
	(segment
		(start 278.605488 -281.892502)
		(end 278.592534 -281.905456)
		(width 0.18288)
		(layer "In11.Cu")
		(net "M_D_CPU0_SA_DQ<28>")
	)
	(segment
		(start 331.737462 -267.328142)
		(end 331.404468 -267.661136)
		(width 0.088646)
		(layer "In11.Cu")
		(net "M_D_CPU0_SA_DQ<28>")
	)
	(segment
		(start 313.715654 -278.445976)
		(end 313.555634 -278.605996)
		(width 0.18288)
		(layer "In11.Cu")
		(net "M_D_CPU0_SA_DQ<28>")
	)
	(segment
		(start 325.343774 -268.257274)
		(end 315.815726 -277.785322)
		(width 0.18288)
		(layer "In11.Cu")
		(net "M_D_CPU0_SA_DQ<28>")
	)
	(segment
		(start 301.899574 -280.928826)
		(end 301.706534 -281.121866)
		(width 0.18288)
		(layer "In11.Cu")
		(net "M_D_CPU0_SA_DQ<28>")
	)
	(segment
		(start 272.843752 -282.598368)
		(end 269.617952 -282.598368)
		(width 0.18288)
		(layer "In11.Cu")
		(net "M_D_CPU0_SA_DQ<28>")
	)
	(segment
		(start 305.143916 -280.622502)
		(end 305.143916 -280.156666)
		(width 0.18288)
		(layer "In11.Cu")
		(net "M_D_CPU0_SA_DQ<28>")
	)
	(segment
		(start 301.005494 -281.121866)
		(end 300.812454 -280.928826)
		(width 0.18288)
		(layer "In11.Cu")
		(net "M_D_CPU0_SA_DQ<28>")
	)
	(segment
		(start 290.971732 -282.357576)
		(end 290.778692 -282.550616)
		(width 0.18288)
		(layer "In11.Cu")
		(net "M_D_CPU0_SA_DQ<28>")
	)
	(segment
		(start 345.867736 -266.66825)
		(end 345.78036 -266.617704)
		(width 0.088646)
		(layer "In11.Cu")
		(net "M_D_CPU0_SA_DQ<28>")
	)
	(segment
		(start 342.975946 -266.62634)
		(end 342.961214 -266.617704)
		(width 0.088646)
		(layer "In11.Cu")
		(net "M_D_CPU0_SA_DQ<28>")
	)
	(segment
		(start 291.164772 -281.767026)
		(end 290.971732 -281.960066)
		(width 0.18288)
		(layer "In11.Cu")
		(net "M_D_CPU0_SA_DQ<28>")
	)
	(segment
		(start 307.203094 -279.963626)
		(end 306.037996 -279.963626)
		(width 0.18288)
		(layer "In11.Cu")
		(net "M_D_CPU0_SA_DQ<28>")
	)
	(segment
		(start 331.211428 -268.257274)
		(end 330.903072 -268.257274)
		(width 0.088646)
		(layer "In11.Cu")
		(net "M_D_CPU0_SA_DQ<28>")
	)
	(segment
		(start 312.702194 -278.445976)
		(end 311.643776 -278.445976)
		(width 0.18288)
		(layer "In11.Cu")
		(net "M_D_CPU0_SA_DQ<28>")
	)
	(segment
		(start 290.971732 -281.960066)
		(end 290.971732 -282.357576)
		(width 0.18288)
		(layer "In11.Cu")
		(net "M_D_CPU0_SA_DQ<28>")
	)
	(segment
		(start 305.844956 -280.622502)
		(end 305.651916 -280.815542)
		(width 0.18288)
		(layer "In11.Cu")
		(net "M_D_CPU0_SA_DQ<28>")
	)
	(segment
		(start 304.950876 -279.963626)
		(end 304.028094 -279.963626)
		(width 0.18288)
		(layer "In11.Cu")
		(net "M_D_CPU0_SA_DQ<28>")
	)
	(segment
		(start 267.858494 -282.986226)
		(end 265.398758 -282.986226)
		(width 0.18288)
		(layer "In11.Cu")
		(net "M_D_CPU0_SA_DQ<28>")
	)
	(segment
		(start 305.844956 -280.156666)
		(end 305.844956 -280.622502)
		(width 0.18288)
		(layer "In11.Cu")
		(net "M_D_CPU0_SA_DQ<28>")
	)
	(segment
		(start 340.156546 -266.62634)
		(end 340.141814 -266.617704)
		(width 0.088646)
		(layer "In11.Cu")
		(net "M_D_CPU0_SA_DQ<28>")
	)
	(segment
		(start 269.473934 -282.742386)
		(end 268.102334 -282.742386)
		(width 0.18288)
		(layer "In11.Cu")
		(net "M_D_CPU0_SA_DQ<28>")
	)
	(segment
		(start 298.275502 -281.042618)
		(end 297.682666 -281.635454)
		(width 0.18288)
		(layer "In11.Cu")
		(net "M_D_CPU0_SA_DQ<28>")
	)
	(segment
		(start 339.212174 -266.6238)
		(end 339.20176 -266.617704)
		(width 0.088646)
		(layer "In11.Cu")
		(net "M_D_CPU0_SA_DQ<28>")
	)
	(segment
		(start 301.198534 -281.639772)
		(end 301.005494 -281.446732)
		(width 0.18288)
		(layer "In11.Cu")
		(net "M_D_CPU0_SA_DQ<28>")
	)
	(segment
		(start 303.062894 -280.928826)
		(end 301.899574 -280.928826)
		(width 0.18288)
		(layer "In11.Cu")
		(net "M_D_CPU0_SA_DQ<28>")
	)
	(segment
		(start 293.389812 -281.892502)
		(end 293.375588 -281.906726)
		(width 0.18288)
		(layer "In11.Cu")
		(net "M_D_CPU0_SA_DQ<28>")
	)
	(segment
		(start 269.617952 -282.598368)
		(end 269.473934 -282.742386)
		(width 0.18288)
		(layer "In11.Cu")
		(net "M_D_CPU0_SA_DQ<28>")
	)
	(segment
		(start 285.621222 -280.911554)
		(end 284.995366 -280.911554)
		(width 0.18288)
		(layer "In11.Cu")
		(net "M_D_CPU0_SA_DQ<28>")
	)
	(segment
		(start 299.862494 -280.928826)
		(end 299.748702 -281.042618)
		(width 0.18288)
		(layer "In11.Cu")
		(net "M_D_CPU0_SA_DQ<28>")
	)
	(segment
		(start 332.131416 -266.566904)
		(end 331.737462 -266.960858)
		(width 0.088646)
		(layer "In11.Cu")
		(net "M_D_CPU0_SA_DQ<28>")
	)
	(segment
		(start 301.706534 -281.121866)
		(end 301.706534 -281.446732)
		(width 0.18288)
		(layer "In11.Cu")
		(net "M_D_CPU0_SA_DQ<28>")
	)
	(segment
		(start 290.270692 -282.032964)
		(end 289.699954 -281.462226)
		(width 0.18288)
		(layer "In11.Cu")
		(net "M_D_CPU0_SA_DQ<28>")
	)
	(segment
		(start 341.096346 -266.62634)
		(end 341.081614 -266.617704)
		(width 0.088646)
		(layer "In11.Cu")
		(net "M_D_CPU0_SA_DQ<28>")
	)
	(segment
		(start 331.404468 -268.064234)
		(end 331.211428 -268.257274)
		(width 0.088646)
		(layer "In11.Cu")
		(net "M_D_CPU0_SA_DQ<28>")
	)
	(segment
		(start 306.037996 -279.963626)
		(end 305.844956 -280.156666)
		(width 0.18288)
		(layer "In11.Cu")
		(net "M_D_CPU0_SA_DQ<28>")
	)
	(segment
		(start 315.815726 -277.785322)
		(end 314.977018 -277.785322)
		(width 0.18288)
		(layer "In11.Cu")
		(net "M_D_CPU0_SA_DQ<28>")
	)
	(segment
		(start 284.995366 -280.911554)
		(end 284.864302 -281.042618)
		(width 0.18288)
		(layer "In11.Cu")
		(net "M_D_CPU0_SA_DQ<28>")
	)
	(segment
		(start 273.598894 -281.843226)
		(end 272.843752 -282.598368)
		(width 0.18288)
		(layer "In11.Cu")
		(net "M_D_CPU0_SA_DQ<28>")
	)
	(segment
		(start 342.036146 -266.62634)
		(end 342.021414 -266.617704)
		(width 0.088646)
		(layer "In11.Cu")
		(net "M_D_CPU0_SA_DQ<28>")
	)
	(segment
		(start 277.166324 -281.905456)
		(end 277.104094 -281.843226)
		(width 0.18288)
		(layer "In11.Cu")
		(net "M_D_CPU0_SA_DQ<28>")
	)
	(segment
		(start 290.463732 -282.550616)
		(end 290.270692 -282.357576)
		(width 0.18288)
		(layer "In11.Cu")
		(net "M_D_CPU0_SA_DQ<28>")
	)
	(segment
		(start 314.977018 -277.785322)
		(end 314.316364 -278.445976)
		(width 0.18288)
		(layer "In11.Cu")
		(net "M_D_CPU0_SA_DQ<28>")
	)
	(segment
		(start 297.682666 -281.635454)
		(end 295.871138 -281.635454)
		(width 0.18288)
		(layer "In11.Cu")
		(net "M_D_CPU0_SA_DQ<28>")
	)
	(segment
		(start 301.005494 -281.446732)
		(end 301.005494 -281.121866)
		(width 0.18288)
		(layer "In11.Cu")
		(net "M_D_CPU0_SA_DQ<28>")
	)
	(segment
		(start 332.435962 -266.566904)
		(end 332.131416 -266.566904)
		(width 0.088646)
		(layer "In11.Cu")
		(net "M_D_CPU0_SA_DQ<28>")
	)
	(segment
		(start 331.737462 -266.960858)
		(end 331.737462 -267.328142)
		(width 0.088646)
		(layer "In11.Cu")
		(net "M_D_CPU0_SA_DQ<28>")
	)
	(segment
		(start 288.864294 -281.462226)
		(end 288.381694 -280.979626)
		(width 0.18288)
		(layer "In11.Cu")
		(net "M_D_CPU0_SA_DQ<28>")
	)
	(segment
		(start 305.143916 -280.156666)
		(end 304.950876 -279.963626)
		(width 0.18288)
		(layer "In11.Cu")
		(net "M_D_CPU0_SA_DQ<28>")
	)
	(segment
		(start 291.874194 -281.906726)
		(end 291.734494 -281.767026)
		(width 0.18288)
		(layer "In11.Cu")
		(net "M_D_CPU0_SA_DQ<28>")
	)
	(segment
		(start 290.270692 -282.357576)
		(end 290.270692 -282.032964)
		(width 0.18288)
		(layer "In11.Cu")
		(net "M_D_CPU0_SA_DQ<28>")
	)
	(segment
		(start 299.748702 -281.042618)
		(end 298.275502 -281.042618)
		(width 0.18288)
		(layer "In11.Cu")
		(net "M_D_CPU0_SA_DQ<28>")
	)
	(segment
		(start 301.706534 -281.446732)
		(end 301.513494 -281.639772)
		(width 0.18288)
		(layer "In11.Cu")
		(net "M_D_CPU0_SA_DQ<28>")
	)
	(segment
		(start 293.375588 -281.906726)
		(end 291.874194 -281.906726)
		(width 0.18288)
		(layer "In11.Cu")
		(net "M_D_CPU0_SA_DQ<28>")
	)
	(segment
		(start 278.592534 -281.905456)
		(end 277.166324 -281.905456)
		(width 0.18288)
		(layer "In11.Cu")
		(net "M_D_CPU0_SA_DQ<28>")
	)
	(segment
		(start 284.864302 -281.042618)
		(end 283.402278 -281.042618)
		(width 0.18288)
		(layer "In11.Cu")
		(net "M_D_CPU0_SA_DQ<28>")
	)
	(segment
		(start 300.812454 -280.928826)
		(end 299.862494 -280.928826)
		(width 0.18288)
		(layer "In11.Cu")
		(net "M_D_CPU0_SA_DQ<28>")
	)
	(segment
		(start 307.434996 -280.195528)
		(end 307.203094 -279.963626)
		(width 0.18288)
		(layer "In11.Cu")
		(net "M_D_CPU0_SA_DQ<28>")
	)
	(segment
		(start 311.643776 -278.445976)
		(end 310.79694 -279.292812)
		(width 0.18288)
		(layer "In11.Cu")
		(net "M_D_CPU0_SA_DQ<28>")
	)
	(segment
		(start 314.316364 -278.445976)
		(end 313.715654 -278.445976)
		(width 0.18288)
		(layer "In11.Cu")
		(net "M_D_CPU0_SA_DQ<28>")
	)
	(segment
		(start 289.699954 -281.462226)
		(end 288.864294 -281.462226)
		(width 0.18288)
		(layer "In11.Cu")
		(net "M_D_CPU0_SA_DQ<28>")
	)
	(segment
		(start 285.689294 -280.979626)
		(end 285.621222 -280.911554)
		(width 0.18288)
		(layer "In11.Cu")
		(net "M_D_CPU0_SA_DQ<28>")
	)
	(segment
		(start 343.915746 -266.62634)
		(end 343.901014 -266.617704)
		(width 0.088646)
		(layer "In11.Cu")
		(net "M_D_CPU0_SA_DQ<28>")
	)
	(segment
		(start 346.074746 -266.704064)
		(end 345.867736 -266.66825)
		(width 0.088646)
		(layer "In11.Cu")
		(net "M_D_CPU0_SA_DQ<28>")
	)
	(segment
		(start 288.381694 -280.979626)
		(end 285.689294 -280.979626)
		(width 0.18288)
		(layer "In11.Cu")
		(net "M_D_CPU0_SA_DQ<28>")
	)
	(segment
		(start 280.610564 -281.808428)
		(end 280.52649 -281.892502)
		(width 0.18288)
		(layer "In11.Cu")
		(net "M_D_CPU0_SA_DQ<28>")
	)
	(segment
		(start 295.61409 -281.892502)
		(end 293.389812 -281.892502)
		(width 0.18288)
		(layer "In11.Cu")
		(net "M_D_CPU0_SA_DQ<28>")
	)
	(segment
		(start 291.734494 -281.767026)
		(end 291.164772 -281.767026)
		(width 0.18288)
		(layer "In11.Cu")
		(net "M_D_CPU0_SA_DQ<28>")
	)
	(segment
		(start 308.009544 -280.195528)
		(end 307.434996 -280.195528)
		(width 0.18288)
		(layer "In11.Cu")
		(net "M_D_CPU0_SA_DQ<28>")
	)
	(segment
		(start 344.851228 -266.6238)
		(end 344.840814 -266.617704)
		(width 0.088646)
		(layer "In11.Cu")
		(net "M_D_CPU0_SA_DQ<28>")
	)
	(segment
		(start 301.513494 -281.639772)
		(end 301.198534 -281.639772)
		(width 0.18288)
		(layer "In11.Cu")
		(net "M_D_CPU0_SA_DQ<28>")
	)
	(segment
		(start 290.778692 -282.550616)
		(end 290.463732 -282.550616)
		(width 0.18288)
		(layer "In11.Cu")
		(net "M_D_CPU0_SA_DQ<28>")
	)
	(segment
		(start 280.52649 -281.892502)
		(end 278.605488 -281.892502)
		(width 0.18288)
		(layer "In11.Cu")
		(net "M_D_CPU0_SA_DQ<28>")
	)
	(segment
		(start 282.636468 -281.808428)
		(end 280.610564 -281.808428)
		(width 0.18288)
		(layer "In11.Cu")
		(net "M_D_CPU0_SA_DQ<28>")
	)
	(segment
		(start 304.028094 -279.963626)
		(end 303.062894 -280.928826)
		(width 0.18288)
		(layer "In11.Cu")
		(net "M_D_CPU0_SA_DQ<28>")
	)
	(segment
		(start 305.336956 -280.815542)
		(end 305.143916 -280.622502)
		(width 0.18288)
		(layer "In11.Cu")
		(net "M_D_CPU0_SA_DQ<28>")
	)
	(segment
		(start 265.398758 -282.986226)
		(end 264.729214 -282.316682)
		(width 0.18288)
		(layer "In11.Cu")
		(net "M_D_CPU0_SA_DQ<28>")
	)
	(segment
		(start 268.102334 -282.742386)
		(end 267.858494 -282.986226)
		(width 0.18288)
		(layer "In11.Cu")
		(net "M_D_CPU0_SA_DQ<28>")
	)
	(arc
		(start 345.78036 -266.617704)
		(mid 345.593162 -266.567527)
		(end 345.405964 -266.617704)
		(width 0.088646)
		(layer "In11.Cu")
		(net "M_D_CPU0_SA_DQ<28>")
	)
	(arc
		(start 334.128364 -266.617704)
		(mid 333.845662 -266.69348)
		(end 333.56296 -266.617704)
		(width 0.088646)
		(layer "In11.Cu")
		(net "M_D_CPU0_SA_DQ<28>")
	)
	(arc
		(start 343.901014 -266.617704)
		(mid 343.713816 -266.567527)
		(end 343.526618 -266.617704)
		(width 0.088646)
		(layer "In11.Cu")
		(net "M_D_CPU0_SA_DQ<28>")
	)
	(arc
		(start 341.081614 -266.617704)
		(mid 340.894416 -266.567527)
		(end 340.707218 -266.617704)
		(width 0.088646)
		(layer "In11.Cu")
		(net "M_D_CPU0_SA_DQ<28>")
	)
	(arc
		(start 338.26196 -266.617704)
		(mid 338.074762 -266.567527)
		(end 337.887564 -266.617704)
		(width 0.088646)
		(layer "In11.Cu")
		(net "M_D_CPU0_SA_DQ<28>")
	)
	(arc
		(start 340.141814 -266.617704)
		(mid 339.954616 -266.567527)
		(end 339.767418 -266.617704)
		(width 0.088646)
		(layer "In11.Cu")
		(net "M_D_CPU0_SA_DQ<28>")
	)
	(arc
		(start 342.586818 -266.617704)
		(mid 342.312619 -266.693539)
		(end 342.036146 -266.62634)
		(width 0.088646)
		(layer "In11.Cu")
		(net "M_D_CPU0_SA_DQ<28>")
	)
	(arc
		(start 343.526618 -266.617704)
		(mid 343.252419 -266.693539)
		(end 342.975946 -266.62634)
		(width 0.088646)
		(layer "In11.Cu")
		(net "M_D_CPU0_SA_DQ<28>")
	)
	(arc
		(start 338.827364 -266.617704)
		(mid 338.544662 -266.69348)
		(end 338.26196 -266.617704)
		(width 0.088646)
		(layer "In11.Cu")
		(net "M_D_CPU0_SA_DQ<28>")
	)
	(arc
		(start 342.021414 -266.617704)
		(mid 341.834216 -266.567527)
		(end 341.647018 -266.617704)
		(width 0.088646)
		(layer "In11.Cu")
		(net "M_D_CPU0_SA_DQ<28>")
	)
	(arc
		(start 335.068164 -266.617704)
		(mid 334.785462 -266.69348)
		(end 334.50276 -266.617704)
		(width 0.088646)
		(layer "In11.Cu")
		(net "M_D_CPU0_SA_DQ<28>")
	)
	(arc
		(start 344.840814 -266.617704)
		(mid 344.653616 -266.567527)
		(end 344.466418 -266.617704)
		(width 0.088646)
		(layer "In11.Cu")
		(net "M_D_CPU0_SA_DQ<28>")
	)
	(arc
		(start 346.533216 -266.941808)
		(mid 346.322378 -266.787445)
		(end 346.074746 -266.704064)
		(width 0.088646)
		(layer "In11.Cu")
		(net "M_D_CPU0_SA_DQ<28>")
	)
	(arc
		(start 345.405964 -266.617704)
		(mid 345.129405 -266.693447)
		(end 344.851228 -266.6238)
		(width 0.088646)
		(layer "In11.Cu")
		(net "M_D_CPU0_SA_DQ<28>")
	)
	(arc
		(start 336.947764 -266.617704)
		(mid 336.665062 -266.69348)
		(end 336.38236 -266.617704)
		(width 0.088646)
		(layer "In11.Cu")
		(net "M_D_CPU0_SA_DQ<28>")
	)
	(arc
		(start 340.707218 -266.617704)
		(mid 340.433019 -266.693539)
		(end 340.156546 -266.62634)
		(width 0.088646)
		(layer "In11.Cu")
		(net "M_D_CPU0_SA_DQ<28>")
	)
	(arc
		(start 332.62316 -266.617704)
		(mid 332.532909 -266.579957)
		(end 332.435962 -266.566904)
		(width 0.088646)
		(layer "In11.Cu")
		(net "M_D_CPU0_SA_DQ<28>")
	)
	(arc
		(start 335.44256 -266.617704)
		(mid 335.255362 -266.567527)
		(end 335.068164 -266.617704)
		(width 0.088646)
		(layer "In11.Cu")
		(net "M_D_CPU0_SA_DQ<28>")
	)
	(arc
		(start 337.32216 -266.617704)
		(mid 337.134962 -266.567527)
		(end 336.947764 -266.617704)
		(width 0.088646)
		(layer "In11.Cu")
		(net "M_D_CPU0_SA_DQ<28>")
	)
	(arc
		(start 336.007964 -266.617704)
		(mid 335.725262 -266.69348)
		(end 335.44256 -266.617704)
		(width 0.088646)
		(layer "In11.Cu")
		(net "M_D_CPU0_SA_DQ<28>")
	)
	(arc
		(start 334.50276 -266.617704)
		(mid 334.315562 -266.567527)
		(end 334.128364 -266.617704)
		(width 0.088646)
		(layer "In11.Cu")
		(net "M_D_CPU0_SA_DQ<28>")
	)
	(arc
		(start 337.887564 -266.617704)
		(mid 337.604862 -266.69348)
		(end 337.32216 -266.617704)
		(width 0.088646)
		(layer "In11.Cu")
		(net "M_D_CPU0_SA_DQ<28>")
	)
	(arc
		(start 333.188564 -266.617704)
		(mid 332.905862 -266.69348)
		(end 332.62316 -266.617704)
		(width 0.088646)
		(layer "In11.Cu")
		(net "M_D_CPU0_SA_DQ<28>")
	)
	(arc
		(start 333.56296 -266.617704)
		(mid 333.375762 -266.567527)
		(end 333.188564 -266.617704)
		(width 0.088646)
		(layer "In11.Cu")
		(net "M_D_CPU0_SA_DQ<28>")
	)
	(arc
		(start 339.767418 -266.617704)
		(mid 339.490605 -266.693574)
		(end 339.212174 -266.6238)
		(width 0.088646)
		(layer "In11.Cu")
		(net "M_D_CPU0_SA_DQ<28>")
	)
	(arc
		(start 336.38236 -266.617704)
		(mid 336.195162 -266.567527)
		(end 336.007964 -266.617704)
		(width 0.088646)
		(layer "In11.Cu")
		(net "M_D_CPU0_SA_DQ<28>")
	)
	(arc
		(start 339.20176 -266.617704)
		(mid 339.014562 -266.567527)
		(end 338.827364 -266.617704)
		(width 0.088646)
		(layer "In11.Cu")
		(net "M_D_CPU0_SA_DQ<28>")
	)
	(arc
		(start 344.466418 -266.617704)
		(mid 344.192219 -266.693539)
		(end 343.915746 -266.62634)
		(width 0.088646)
		(layer "In11.Cu")
		(net "M_D_CPU0_SA_DQ<28>")
	)
	(arc
		(start 342.961214 -266.617704)
		(mid 342.774016 -266.567527)
		(end 342.586818 -266.617704)
		(width 0.088646)
		(layer "In11.Cu")
		(net "M_D_CPU0_SA_DQ<28>")
	)
	(arc
		(start 341.647018 -266.617704)
		(mid 341.372819 -266.693539)
		(end 341.096346 -266.62634)
		(width 0.088646)
		(layer "In11.Cu")
		(net "M_D_CPU0_SA_DQ<28>")
	)
	(segment
		(start 262.146288 -286.155892)
		(end 262.003794 -286.013398)
		(width 0.20066)
		(layer "F.Cu")
		(net "M_D_CPU0_SA_DQ<27>")
	)
	(segment
		(start 262.50011 -286.155892)
		(end 262.146288 -286.155892)
		(width 0.20066)
		(layer "F.Cu")
		(net "M_D_CPU0_SA_DQ<27>")
	)
	(segment
		(start 264.825226 -286.141668)
		(end 262.752332 -286.141668)
		(width 0.1016)
		(layer "F.Cu")
		(net "M_D_CPU0_SA_DQ<27>")
	)
	(segment
		(start 262.514334 -286.141668)
		(end 262.50011 -286.155892)
		(width 0.101854)
		(layer "F.Cu")
		(net "M_D_CPU0_SA_DQ<27>")
	)
	(segment
		(start 265.518646 -285.840932)
		(end 265.518646 -285.99257)
		(width 0.20066)
		(layer "F.Cu")
		(net "M_D_CPU0_SA_DQ<27>")
	)
	(segment
		(start 268.829282 -285.716726)
		(end 267.724382 -285.716726)
		(width 0.20066)
		(layer "F.Cu")
		(net "M_D_CPU0_SA_DQ<27>")
	)
	(segment
		(start 261.87781 -285.716726)
		(end 260.180582 -285.716726)
		(width 0.20066)
		(layer "F.Cu")
		(net "M_D_CPU0_SA_DQ<27>")
	)
	(segment
		(start 266.042394 -285.712408)
		(end 265.64717 -285.712408)
		(width 0.20066)
		(layer "F.Cu")
		(net "M_D_CPU0_SA_DQ<27>")
	)
	(segment
		(start 262.003794 -286.013398)
		(end 262.003794 -285.84271)
		(width 0.20066)
		(layer "F.Cu")
		(net "M_D_CPU0_SA_DQ<27>")
	)
	(segment
		(start 266.25423 -285.924244)
		(end 266.042394 -285.712408)
		(width 0.20066)
		(layer "F.Cu")
		(net "M_D_CPU0_SA_DQ<27>")
	)
	(segment
		(start 265.369548 -286.141668)
		(end 264.825226 -286.141668)
		(width 0.20066)
		(layer "F.Cu")
		(net "M_D_CPU0_SA_DQ<27>")
	)
	(segment
		(start 348.412816 -268.034008)
		(end 348.412816 -268.569694)
		(width 0.20066)
		(layer "F.Cu")
		(net "M_D_CPU0_SA_DQ<27>")
	)
	(segment
		(start 348.412562 -268.033754)
		(end 348.412816 -268.034008)
		(width 0.20066)
		(layer "F.Cu")
		(net "M_D_CPU0_SA_DQ<27>")
	)
	(segment
		(start 265.518646 -285.99257)
		(end 265.369548 -286.141668)
		(width 0.20066)
		(layer "F.Cu")
		(net "M_D_CPU0_SA_DQ<27>")
	)
	(segment
		(start 262.003794 -285.84271)
		(end 261.87781 -285.716726)
		(width 0.20066)
		(layer "F.Cu")
		(net "M_D_CPU0_SA_DQ<27>")
	)
	(segment
		(start 266.700762 -285.924244)
		(end 266.25423 -285.924244)
		(width 0.20066)
		(layer "F.Cu")
		(net "M_D_CPU0_SA_DQ<27>")
	)
	(segment
		(start 267.724382 -285.716726)
		(end 266.90828 -285.716726)
		(width 0.20066)
		(layer "F.Cu")
		(net "M_D_CPU0_SA_DQ<27>")
	)
	(segment
		(start 265.64717 -285.712408)
		(end 265.518646 -285.840932)
		(width 0.20066)
		(layer "F.Cu")
		(net "M_D_CPU0_SA_DQ<27>")
	)
	(segment
		(start 262.752332 -286.141668)
		(end 262.514334 -286.141668)
		(width 0.101854)
		(layer "F.Cu")
		(net "M_D_CPU0_SA_DQ<27>")
	)
	(segment
		(start 266.90828 -285.716726)
		(end 266.700762 -285.924244)
		(width 0.20066)
		(layer "F.Cu")
		(net "M_D_CPU0_SA_DQ<27>")
	)
	(segment
		(start 272.439384 -286.304736)
		(end 271.613884 -286.304736)
		(width 0.18288)
		(layer "In11.Cu")
		(net "M_D_CPU0_SA_DQ<27>")
	)
	(segment
		(start 341.652606 -268.897608)
		(end 341.646764 -268.894052)
		(width 0.088646)
		(layer "In11.Cu")
		(net "M_D_CPU0_SA_DQ<27>")
	)
	(segment
		(start 280.183844 -287.075626)
		(end 280.100786 -286.992568)
		(width 0.18288)
		(layer "In11.Cu")
		(net "M_D_CPU0_SA_DQ<27>")
	)
	(segment
		(start 311.083452 -282.236672)
		(end 311.083452 -282.680664)
		(width 0.18288)
		(layer "In11.Cu")
		(net "M_D_CPU0_SA_DQ<27>")
	)
	(segment
		(start 272.913094 -285.831026)
		(end 272.439384 -286.304736)
		(width 0.18288)
		(layer "In11.Cu")
		(net "M_D_CPU0_SA_DQ<27>")
	)
	(segment
		(start 346.735146 -268.253972)
		(end 346.720414 -268.245336)
		(width 0.088646)
		(layer "In11.Cu")
		(net "M_D_CPU0_SA_DQ<27>")
	)
	(segment
		(start 283.859986 -286.14116)
		(end 283.858462 -286.142684)
		(width 0.18288)
		(layer "In11.Cu")
		(net "M_D_CPU0_SA_DQ<27>")
	)
	(segment
		(start 290.877244 -285.577026)
		(end 290.684204 -285.383986)
		(width 0.18288)
		(layer "In11.Cu")
		(net "M_D_CPU0_SA_DQ<27>")
	)
	(segment
		(start 314.87364 -281.885644)
		(end 311.43448 -281.885644)
		(width 0.18288)
		(layer "In11.Cu")
		(net "M_D_CPU0_SA_DQ<27>")
	)
	(segment
		(start 330.903072 -270.421354)
		(end 326.33793 -270.421354)
		(width 0.18288)
		(layer "In11.Cu")
		(net "M_D_CPU0_SA_DQ<27>")
	)
	(segment
		(start 274.881848 -285.358586)
		(end 274.688808 -285.551626)
		(width 0.18288)
		(layer "In11.Cu")
		(net "M_D_CPU0_SA_DQ<27>")
	)
	(segment
		(start 340.156546 -268.885416)
		(end 340.141814 -268.894052)
		(width 0.088646)
		(layer "In11.Cu")
		(net "M_D_CPU0_SA_DQ<27>")
	)
	(segment
		(start 299.05833 -286.142684)
		(end 299.056806 -286.14116)
		(width 0.18288)
		(layer "In11.Cu")
		(net "M_D_CPU0_SA_DQ<27>")
	)
	(segment
		(start 299.811694 -286.288226)
		(end 299.666152 -286.142684)
		(width 0.18288)
		(layer "In11.Cu")
		(net "M_D_CPU0_SA_DQ<27>")
	)
	(segment
		(start 271.613884 -286.304736)
		(end 271.420844 -286.111696)
		(width 0.18288)
		(layer "In11.Cu")
		(net "M_D_CPU0_SA_DQ<27>")
	)
	(segment
		(start 277.510494 -286.593026)
		(end 276.469094 -285.551626)
		(width 0.18288)
		(layer "In11.Cu")
		(net "M_D_CPU0_SA_DQ<27>")
	)
	(segment
		(start 309.703978 -283.748226)
		(end 304.70475 -283.748226)
		(width 0.18288)
		(layer "In11.Cu")
		(net "M_D_CPU0_SA_DQ<27>")
	)
	(segment
		(start 284.793436 -286.255968)
		(end 284.680152 -286.142684)
		(width 0.18288)
		(layer "In11.Cu")
		(net "M_D_CPU0_SA_DQ<27>")
	)
	(segment
		(start 282.082494 -287.075626)
		(end 280.183844 -287.075626)
		(width 0.18288)
		(layer "In11.Cu")
		(net "M_D_CPU0_SA_DQ<27>")
	)
	(segment
		(start 300.980094 -285.272226)
		(end 300.980094 -285.678626)
		(width 0.18288)
		(layer "In11.Cu")
		(net "M_D_CPU0_SA_DQ<27>")
	)
	(segment
		(start 346.346018 -268.245336)
		(end 346.294456 -268.275054)
		(width 0.088646)
		(layer "In11.Cu")
		(net "M_D_CPU0_SA_DQ<27>")
	)
	(segment
		(start 283.97327 -286.142684)
		(end 283.971746 -286.14116)
		(width 0.18288)
		(layer "In11.Cu")
		(net "M_D_CPU0_SA_DQ<27>")
	)
	(segment
		(start 331.884528 -269.925292)
		(end 331.388466 -270.421354)
		(width 0.088646)
		(layer "In11.Cu")
		(net "M_D_CPU0_SA_DQ<27>")
	)
	(segment
		(start 283.971746 -286.14116)
		(end 283.859986 -286.14116)
		(width 0.18288)
		(layer "In11.Cu")
		(net "M_D_CPU0_SA_DQ<27>")
	)
	(segment
		(start 276.469094 -285.551626)
		(end 275.775928 -285.551626)
		(width 0.18288)
		(layer "In11.Cu")
		(net "M_D_CPU0_SA_DQ<27>")
	)
	(segment
		(start 290.491164 -284.87497)
		(end 290.176204 -284.87497)
		(width 0.18288)
		(layer "In11.Cu")
		(net "M_D_CPU0_SA_DQ<27>")
	)
	(segment
		(start 338.272374 -268.887956)
		(end 338.26196 -268.894052)
		(width 0.088646)
		(layer "In11.Cu")
		(net "M_D_CPU0_SA_DQ<27>")
	)
	(segment
		(start 345.405964 -268.894052)
		(end 345.400122 -268.89075)
		(width 0.088646)
		(layer "In11.Cu")
		(net "M_D_CPU0_SA_DQ<27>")
	)
	(segment
		(start 344.466164 -268.894052)
		(end 344.460322 -268.89075)
		(width 0.088646)
		(layer "In11.Cu")
		(net "M_D_CPU0_SA_DQ<27>")
	)
	(segment
		(start 269.417292 -286.304736)
		(end 268.829282 -285.716726)
		(width 0.18288)
		(layer "In11.Cu")
		(net "M_D_CPU0_SA_DQ<27>")
	)
	(segment
		(start 278.297894 -286.593026)
		(end 277.510494 -286.593026)
		(width 0.18288)
		(layer "In11.Cu")
		(net "M_D_CPU0_SA_DQ<27>")
	)
	(segment
		(start 274.881848 -285.115762)
		(end 274.881848 -285.358586)
		(width 0.18288)
		(layer "In11.Cu")
		(net "M_D_CPU0_SA_DQ<27>")
	)
	(segment
		(start 271.420844 -285.72333)
		(end 271.227804 -285.53029)
		(width 0.18288)
		(layer "In11.Cu")
		(net "M_D_CPU0_SA_DQ<27>")
	)
	(segment
		(start 300.370494 -286.288226)
		(end 299.811694 -286.288226)
		(width 0.18288)
		(layer "In11.Cu")
		(net "M_D_CPU0_SA_DQ<27>")
	)
	(segment
		(start 346.133928 -268.471904)
		(end 346.101162 -268.570456)
		(width 0.088646)
		(layer "In11.Cu")
		(net "M_D_CPU0_SA_DQ<27>")
	)
	(segment
		(start 343.526364 -268.894052)
		(end 343.520522 -268.89075)
		(width 0.088646)
		(layer "In11.Cu")
		(net "M_D_CPU0_SA_DQ<27>")
	)
	(segment
		(start 295.188386 -286.992568)
		(end 293.601394 -286.992568)
		(width 0.18288)
		(layer "In11.Cu")
		(net "M_D_CPU0_SA_DQ<27>")
	)
	(segment
		(start 331.388466 -270.421354)
		(end 330.903072 -270.421354)
		(width 0.088646)
		(layer "In11.Cu")
		(net "M_D_CPU0_SA_DQ<27>")
	)
	(segment
		(start 288.788094 -285.577026)
		(end 288.432494 -285.221426)
		(width 0.18288)
		(layer "In11.Cu")
		(net "M_D_CPU0_SA_DQ<27>")
	)
	(segment
		(start 299.666152 -286.142684)
		(end 299.05833 -286.142684)
		(width 0.18288)
		(layer "In11.Cu")
		(net "M_D_CPU0_SA_DQ<27>")
	)
	(segment
		(start 270.912844 -285.53029)
		(end 270.719804 -285.72333)
		(width 0.18288)
		(layer "In11.Cu")
		(net "M_D_CPU0_SA_DQ<27>")
	)
	(segment
		(start 283.015436 -286.142684)
		(end 282.082494 -287.075626)
		(width 0.18288)
		(layer "In11.Cu")
		(net "M_D_CPU0_SA_DQ<27>")
	)
	(segment
		(start 285.314644 -286.255968)
		(end 284.793436 -286.255968)
		(width 0.18288)
		(layer "In11.Cu")
		(net "M_D_CPU0_SA_DQ<27>")
	)
	(segment
		(start 344.472006 -268.897608)
		(end 344.466164 -268.894052)
		(width 0.088646)
		(layer "In11.Cu")
		(net "M_D_CPU0_SA_DQ<27>")
	)
	(segment
		(start 288.432494 -285.221426)
		(end 286.349186 -285.221426)
		(width 0.18288)
		(layer "In11.Cu")
		(net "M_D_CPU0_SA_DQ<27>")
	)
	(segment
		(start 345.411806 -268.897608)
		(end 345.405964 -268.894052)
		(width 0.088646)
		(layer "In11.Cu")
		(net "M_D_CPU0_SA_DQ<27>")
	)
	(segment
		(start 289.790124 -285.577026)
		(end 288.788094 -285.577026)
		(width 0.18288)
		(layer "In11.Cu")
		(net "M_D_CPU0_SA_DQ<27>")
	)
	(segment
		(start 275.582888 -285.115762)
		(end 275.389848 -284.922722)
		(width 0.18288)
		(layer "In11.Cu")
		(net "M_D_CPU0_SA_DQ<27>")
	)
	(segment
		(start 297.24731 -287.056068)
		(end 295.251886 -287.056068)
		(width 0.18288)
		(layer "In11.Cu")
		(net "M_D_CPU0_SA_DQ<27>")
	)
	(segment
		(start 298.955206 -286.14116)
		(end 298.953682 -286.142684)
		(width 0.18288)
		(layer "In11.Cu")
		(net "M_D_CPU0_SA_DQ<27>")
	)
	(segment
		(start 270.719804 -285.72333)
		(end 270.719804 -286.111696)
		(width 0.18288)
		(layer "In11.Cu")
		(net "M_D_CPU0_SA_DQ<27>")
	)
	(segment
		(start 286.349186 -285.221426)
		(end 285.314644 -286.255968)
		(width 0.18288)
		(layer "In11.Cu")
		(net "M_D_CPU0_SA_DQ<27>")
	)
	(segment
		(start 332.332838 -268.944598)
		(end 331.884528 -269.392908)
		(width 0.088646)
		(layer "In11.Cu")
		(net "M_D_CPU0_SA_DQ<27>")
	)
	(segment
		(start 280.100786 -286.992568)
		(end 278.697436 -286.992568)
		(width 0.18288)
		(layer "In11.Cu")
		(net "M_D_CPU0_SA_DQ<27>")
	)
	(segment
		(start 347.669104 -268.250416)
		(end 347.660214 -268.245336)
		(width 0.088646)
		(layer "In11.Cu")
		(net "M_D_CPU0_SA_DQ<27>")
	)
	(segment
		(start 275.074888 -284.922722)
		(end 274.881848 -285.115762)
		(width 0.18288)
		(layer "In11.Cu")
		(net "M_D_CPU0_SA_DQ<27>")
	)
	(segment
		(start 289.983164 -285.06801)
		(end 289.983164 -285.383986)
		(width 0.18288)
		(layer "In11.Cu")
		(net "M_D_CPU0_SA_DQ<27>")
	)
	(segment
		(start 298.160694 -286.142684)
		(end 297.24731 -287.056068)
		(width 0.18288)
		(layer "In11.Cu")
		(net "M_D_CPU0_SA_DQ<27>")
	)
	(segment
		(start 298.953682 -286.142684)
		(end 298.160694 -286.142684)
		(width 0.18288)
		(layer "In11.Cu")
		(net "M_D_CPU0_SA_DQ<27>")
	)
	(segment
		(start 304.70475 -283.748226)
		(end 303.89195 -284.561026)
		(width 0.18288)
		(layer "In11.Cu")
		(net "M_D_CPU0_SA_DQ<27>")
	)
	(segment
		(start 273.649694 -285.551626)
		(end 273.370294 -285.831026)
		(width 0.18288)
		(layer "In11.Cu")
		(net "M_D_CPU0_SA_DQ<27>")
	)
	(segment
		(start 275.582888 -285.358586)
		(end 275.582888 -285.115762)
		(width 0.18288)
		(layer "In11.Cu")
		(net "M_D_CPU0_SA_DQ<27>")
	)
	(segment
		(start 278.697436 -286.992568)
		(end 278.297894 -286.593026)
		(width 0.18288)
		(layer "In11.Cu")
		(net "M_D_CPU0_SA_DQ<27>")
	)
	(segment
		(start 300.980094 -285.678626)
		(end 300.370494 -286.288226)
		(width 0.18288)
		(layer "In11.Cu")
		(net "M_D_CPU0_SA_DQ<27>")
	)
	(segment
		(start 293.601394 -286.992568)
		(end 293.328852 -286.720026)
		(width 0.18288)
		(layer "In11.Cu")
		(net "M_D_CPU0_SA_DQ<27>")
	)
	(segment
		(start 290.684204 -285.06801)
		(end 290.491164 -284.87497)
		(width 0.18288)
		(layer "In11.Cu")
		(net "M_D_CPU0_SA_DQ<27>")
	)
	(segment
		(start 342.592406 -268.897608)
		(end 342.586564 -268.894052)
		(width 0.088646)
		(layer "In11.Cu")
		(net "M_D_CPU0_SA_DQ<27>")
	)
	(segment
		(start 311.43448 -281.885644)
		(end 311.083452 -282.236672)
		(width 0.18288)
		(layer "In11.Cu")
		(net "M_D_CPU0_SA_DQ<27>")
	)
	(segment
		(start 283.858462 -286.142684)
		(end 283.015436 -286.142684)
		(width 0.18288)
		(layer "In11.Cu")
		(net "M_D_CPU0_SA_DQ<27>")
	)
	(segment
		(start 311.083452 -282.680664)
		(end 310.236616 -283.5275)
		(width 0.18288)
		(layer "In11.Cu")
		(net "M_D_CPU0_SA_DQ<27>")
	)
	(segment
		(start 303.89195 -284.561026)
		(end 301.691294 -284.561026)
		(width 0.18288)
		(layer "In11.Cu")
		(net "M_D_CPU0_SA_DQ<27>")
	)
	(segment
		(start 270.526764 -286.304736)
		(end 269.417292 -286.304736)
		(width 0.18288)
		(layer "In11.Cu")
		(net "M_D_CPU0_SA_DQ<27>")
	)
	(segment
		(start 290.176204 -284.87497)
		(end 289.983164 -285.06801)
		(width 0.18288)
		(layer "In11.Cu")
		(net "M_D_CPU0_SA_DQ<27>")
	)
	(segment
		(start 289.983164 -285.383986)
		(end 289.790124 -285.577026)
		(width 0.18288)
		(layer "In11.Cu")
		(net "M_D_CPU0_SA_DQ<27>")
	)
	(segment
		(start 310.236616 -283.5275)
		(end 309.703978 -283.748226)
		(width 0.18288)
		(layer "In11.Cu")
		(net "M_D_CPU0_SA_DQ<27>")
	)
	(segment
		(start 284.680152 -286.142684)
		(end 283.97327 -286.142684)
		(width 0.18288)
		(layer "In11.Cu")
		(net "M_D_CPU0_SA_DQ<27>")
	)
	(segment
		(start 271.420844 -286.111696)
		(end 271.420844 -285.72333)
		(width 0.18288)
		(layer "In11.Cu")
		(net "M_D_CPU0_SA_DQ<27>")
	)
	(segment
		(start 271.227804 -285.53029)
		(end 270.912844 -285.53029)
		(width 0.18288)
		(layer "In11.Cu")
		(net "M_D_CPU0_SA_DQ<27>")
	)
	(segment
		(start 293.328852 -286.720026)
		(end 292.699694 -286.720026)
		(width 0.18288)
		(layer "In11.Cu")
		(net "M_D_CPU0_SA_DQ<27>")
	)
	(segment
		(start 299.056806 -286.14116)
		(end 298.955206 -286.14116)
		(width 0.18288)
		(layer "In11.Cu")
		(net "M_D_CPU0_SA_DQ<27>")
	)
	(segment
		(start 275.775928 -285.551626)
		(end 275.582888 -285.358586)
		(width 0.18288)
		(layer "In11.Cu")
		(net "M_D_CPU0_SA_DQ<27>")
	)
	(segment
		(start 292.699694 -286.720026)
		(end 291.556694 -285.577026)
		(width 0.18288)
		(layer "In11.Cu")
		(net "M_D_CPU0_SA_DQ<27>")
	)
	(segment
		(start 342.586564 -268.894052)
		(end 342.580722 -268.89075)
		(width 0.088646)
		(layer "In11.Cu")
		(net "M_D_CPU0_SA_DQ<27>")
	)
	(segment
		(start 291.556694 -285.577026)
		(end 290.877244 -285.577026)
		(width 0.18288)
		(layer "In11.Cu")
		(net "M_D_CPU0_SA_DQ<27>")
	)
	(segment
		(start 326.33793 -270.421354)
		(end 314.87364 -281.885644)
		(width 0.18288)
		(layer "In11.Cu")
		(net "M_D_CPU0_SA_DQ<27>")
	)
	(segment
		(start 275.389848 -284.922722)
		(end 275.074888 -284.922722)
		(width 0.18288)
		(layer "In11.Cu")
		(net "M_D_CPU0_SA_DQ<27>")
	)
	(segment
		(start 273.370294 -285.831026)
		(end 272.913094 -285.831026)
		(width 0.18288)
		(layer "In11.Cu")
		(net "M_D_CPU0_SA_DQ<27>")
	)
	(segment
		(start 301.691294 -284.561026)
		(end 300.980094 -285.272226)
		(width 0.18288)
		(layer "In11.Cu")
		(net "M_D_CPU0_SA_DQ<27>")
	)
	(segment
		(start 348.412816 -268.569694)
		(end 348.1578 -268.569694)
		(width 0.088646)
		(layer "In11.Cu")
		(net "M_D_CPU0_SA_DQ<27>")
	)
	(segment
		(start 270.719804 -286.111696)
		(end 270.526764 -286.304736)
		(width 0.18288)
		(layer "In11.Cu")
		(net "M_D_CPU0_SA_DQ<27>")
	)
	(segment
		(start 290.684204 -285.383986)
		(end 290.684204 -285.06801)
		(width 0.18288)
		(layer "In11.Cu")
		(net "M_D_CPU0_SA_DQ<27>")
	)
	(segment
		(start 274.688808 -285.551626)
		(end 273.649694 -285.551626)
		(width 0.18288)
		(layer "In11.Cu")
		(net "M_D_CPU0_SA_DQ<27>")
	)
	(segment
		(start 343.532206 -268.897608)
		(end 343.526364 -268.894052)
		(width 0.088646)
		(layer "In11.Cu")
		(net "M_D_CPU0_SA_DQ<27>")
	)
	(segment
		(start 332.435962 -268.944598)
		(end 332.332838 -268.944598)
		(width 0.088646)
		(layer "In11.Cu")
		(net "M_D_CPU0_SA_DQ<27>")
	)
	(segment
		(start 331.884528 -269.392908)
		(end 331.884528 -269.925292)
		(width 0.088646)
		(layer "In11.Cu")
		(net "M_D_CPU0_SA_DQ<27>")
	)
	(segment
		(start 295.251886 -287.056068)
		(end 295.188386 -286.992568)
		(width 0.18288)
		(layer "In11.Cu")
		(net "M_D_CPU0_SA_DQ<27>")
	)
	(segment
		(start 341.646764 -268.894052)
		(end 341.640922 -268.89075)
		(width 0.088646)
		(layer "In11.Cu")
		(net "M_D_CPU0_SA_DQ<27>")
	)
	(arc
		(start 344.460322 -268.89075)
		(mid 344.180217 -268.818308)
		(end 343.901014 -268.894052)
		(width 0.088646)
		(layer "In11.Cu")
		(net "M_D_CPU0_SA_DQ<27>")
	)
	(arc
		(start 346.720414 -268.245336)
		(mid 346.533216 -268.195193)
		(end 346.346018 -268.245336)
		(width 0.088646)
		(layer "In11.Cu")
		(net "M_D_CPU0_SA_DQ<27>")
	)
	(arc
		(start 337.32216 -268.894052)
		(mid 337.134962 -268.944195)
		(end 336.947764 -268.894052)
		(width 0.088646)
		(layer "In11.Cu")
		(net "M_D_CPU0_SA_DQ<27>")
	)
	(arc
		(start 341.640922 -268.89075)
		(mid 341.360817 -268.818308)
		(end 341.081614 -268.894052)
		(width 0.088646)
		(layer "In11.Cu")
		(net "M_D_CPU0_SA_DQ<27>")
	)
	(arc
		(start 343.520522 -268.89075)
		(mid 343.240417 -268.818308)
		(end 342.961214 -268.894052)
		(width 0.088646)
		(layer "In11.Cu")
		(net "M_D_CPU0_SA_DQ<27>")
	)
	(arc
		(start 347.78823 -268.36751)
		(mid 347.735265 -268.302254)
		(end 347.669104 -268.250416)
		(width 0.088646)
		(layer "In11.Cu")
		(net "M_D_CPU0_SA_DQ<27>")
	)
	(arc
		(start 338.26196 -268.894052)
		(mid 338.074762 -268.944195)
		(end 337.887564 -268.894052)
		(width 0.088646)
		(layer "In11.Cu")
		(net "M_D_CPU0_SA_DQ<27>")
	)
	(arc
		(start 342.580722 -268.89075)
		(mid 342.300617 -268.818308)
		(end 342.021414 -268.894052)
		(width 0.088646)
		(layer "In11.Cu")
		(net "M_D_CPU0_SA_DQ<27>")
	)
	(arc
		(start 342.961214 -268.894052)
		(mid 342.77729 -268.944306)
		(end 342.592406 -268.897608)
		(width 0.088646)
		(layer "In11.Cu")
		(net "M_D_CPU0_SA_DQ<27>")
	)
	(arc
		(start 346.294456 -268.275054)
		(mid 346.196135 -268.358746)
		(end 346.133928 -268.471904)
		(width 0.088646)
		(layer "In11.Cu")
		(net "M_D_CPU0_SA_DQ<27>")
	)
	(arc
		(start 348.1578 -268.569694)
		(mid 347.947192 -268.515828)
		(end 347.78823 -268.36751)
		(width 0.088646)
		(layer "In11.Cu")
		(net "M_D_CPU0_SA_DQ<27>")
	)
	(arc
		(start 337.887564 -268.894052)
		(mid 337.604862 -268.818276)
		(end 337.32216 -268.894052)
		(width 0.088646)
		(layer "In11.Cu")
		(net "M_D_CPU0_SA_DQ<27>")
	)
	(arc
		(start 336.007964 -268.894052)
		(mid 335.725262 -268.818276)
		(end 335.44256 -268.894052)
		(width 0.088646)
		(layer "In11.Cu")
		(net "M_D_CPU0_SA_DQ<27>")
	)
	(arc
		(start 347.660214 -268.245336)
		(mid 347.473016 -268.195193)
		(end 347.285818 -268.245336)
		(width 0.088646)
		(layer "In11.Cu")
		(net "M_D_CPU0_SA_DQ<27>")
	)
	(arc
		(start 334.128364 -268.894052)
		(mid 333.845662 -268.818276)
		(end 333.56296 -268.894052)
		(width 0.088646)
		(layer "In11.Cu")
		(net "M_D_CPU0_SA_DQ<27>")
	)
	(arc
		(start 344.840814 -268.894052)
		(mid 344.65689 -268.944306)
		(end 344.472006 -268.897608)
		(width 0.088646)
		(layer "In11.Cu")
		(net "M_D_CPU0_SA_DQ<27>")
	)
	(arc
		(start 336.947764 -268.894052)
		(mid 336.665062 -268.818276)
		(end 336.38236 -268.894052)
		(width 0.088646)
		(layer "In11.Cu")
		(net "M_D_CPU0_SA_DQ<27>")
	)
	(arc
		(start 340.141814 -268.894052)
		(mid 339.954616 -268.944195)
		(end 339.767418 -268.894052)
		(width 0.088646)
		(layer "In11.Cu")
		(net "M_D_CPU0_SA_DQ<27>")
	)
	(arc
		(start 336.38236 -268.894052)
		(mid 336.195162 -268.944195)
		(end 336.007964 -268.894052)
		(width 0.088646)
		(layer "In11.Cu")
		(net "M_D_CPU0_SA_DQ<27>")
	)
	(arc
		(start 341.081614 -268.894052)
		(mid 340.894416 -268.944195)
		(end 340.707218 -268.894052)
		(width 0.088646)
		(layer "In11.Cu")
		(net "M_D_CPU0_SA_DQ<27>")
	)
	(arc
		(start 339.767418 -268.894052)
		(mid 339.484716 -268.818276)
		(end 339.202014 -268.894052)
		(width 0.088646)
		(layer "In11.Cu")
		(net "M_D_CPU0_SA_DQ<27>")
	)
	(arc
		(start 338.827618 -268.894052)
		(mid 338.550805 -268.818182)
		(end 338.272374 -268.887956)
		(width 0.088646)
		(layer "In11.Cu")
		(net "M_D_CPU0_SA_DQ<27>")
	)
	(arc
		(start 346.009976 -268.718284)
		(mid 345.901056 -268.813686)
		(end 345.780614 -268.894052)
		(width 0.088646)
		(layer "In11.Cu")
		(net "M_D_CPU0_SA_DQ<27>")
	)
	(arc
		(start 339.202014 -268.894052)
		(mid 339.014816 -268.944195)
		(end 338.827618 -268.894052)
		(width 0.088646)
		(layer "In11.Cu")
		(net "M_D_CPU0_SA_DQ<27>")
	)
	(arc
		(start 342.021414 -268.894052)
		(mid 341.83749 -268.944306)
		(end 341.652606 -268.897608)
		(width 0.088646)
		(layer "In11.Cu")
		(net "M_D_CPU0_SA_DQ<27>")
	)
	(arc
		(start 335.068164 -268.894052)
		(mid 334.785462 -268.818276)
		(end 334.50276 -268.894052)
		(width 0.088646)
		(layer "In11.Cu")
		(net "M_D_CPU0_SA_DQ<27>")
	)
	(arc
		(start 346.101162 -268.570456)
		(mid 346.064172 -268.649672)
		(end 346.009976 -268.718284)
		(width 0.088646)
		(layer "In11.Cu")
		(net "M_D_CPU0_SA_DQ<27>")
	)
	(arc
		(start 347.285818 -268.245336)
		(mid 347.011619 -268.321171)
		(end 346.735146 -268.253972)
		(width 0.088646)
		(layer "In11.Cu")
		(net "M_D_CPU0_SA_DQ<27>")
	)
	(arc
		(start 332.62316 -268.894052)
		(mid 332.532888 -268.931651)
		(end 332.435962 -268.944598)
		(width 0.088646)
		(layer "In11.Cu")
		(net "M_D_CPU0_SA_DQ<27>")
	)
	(arc
		(start 345.780614 -268.894052)
		(mid 345.59669 -268.944306)
		(end 345.411806 -268.897608)
		(width 0.088646)
		(layer "In11.Cu")
		(net "M_D_CPU0_SA_DQ<27>")
	)
	(arc
		(start 345.400122 -268.89075)
		(mid 345.120017 -268.818308)
		(end 344.840814 -268.894052)
		(width 0.088646)
		(layer "In11.Cu")
		(net "M_D_CPU0_SA_DQ<27>")
	)
	(arc
		(start 333.188564 -268.894052)
		(mid 332.905862 -268.818276)
		(end 332.62316 -268.894052)
		(width 0.088646)
		(layer "In11.Cu")
		(net "M_D_CPU0_SA_DQ<27>")
	)
	(arc
		(start 343.901014 -268.894052)
		(mid 343.71709 -268.944306)
		(end 343.532206 -268.897608)
		(width 0.088646)
		(layer "In11.Cu")
		(net "M_D_CPU0_SA_DQ<27>")
	)
	(arc
		(start 333.56296 -268.894052)
		(mid 333.375762 -268.944195)
		(end 333.188564 -268.894052)
		(width 0.088646)
		(layer "In11.Cu")
		(net "M_D_CPU0_SA_DQ<27>")
	)
	(arc
		(start 334.50276 -268.894052)
		(mid 334.315562 -268.944195)
		(end 334.128364 -268.894052)
		(width 0.088646)
		(layer "In11.Cu")
		(net "M_D_CPU0_SA_DQ<27>")
	)
	(arc
		(start 335.44256 -268.894052)
		(mid 335.255362 -268.944195)
		(end 335.068164 -268.894052)
		(width 0.088646)
		(layer "In11.Cu")
		(net "M_D_CPU0_SA_DQ<27>")
	)
	(arc
		(start 340.707218 -268.894052)
		(mid 340.433019 -268.818217)
		(end 340.156546 -268.885416)
		(width 0.088646)
		(layer "In11.Cu")
		(net "M_D_CPU0_SA_DQ<27>")
	)
	(segment
		(start 264.825226 -286.991806)
		(end 262.765286 -286.991806)
		(width 0.1016)
		(layer "F.Cu")
		(net "M_D_CPU0_SA_DQ<26>")
	)
	(segment
		(start 347.942662 -268.847824)
		(end 347.942662 -269.38351)
		(width 0.20066)
		(layer "F.Cu")
		(net "M_D_CPU0_SA_DQ<26>")
	)
	(segment
		(start 268.829282 -287.416748)
		(end 267.724382 -287.416748)
		(width 0.20066)
		(layer "F.Cu")
		(net "M_D_CPU0_SA_DQ<26>")
	)
	(segment
		(start 266.409678 -287.416748)
		(end 266.197842 -287.628584)
		(width 0.20066)
		(layer "F.Cu")
		(net "M_D_CPU0_SA_DQ<26>")
	)
	(segment
		(start 261.327646 -287.416748)
		(end 260.180582 -287.416748)
		(width 0.20066)
		(layer "F.Cu")
		(net "M_D_CPU0_SA_DQ<26>")
	)
	(segment
		(start 265.769344 -287.628584)
		(end 265.601958 -287.461198)
		(width 0.20066)
		(layer "F.Cu")
		(net "M_D_CPU0_SA_DQ<26>")
	)
	(segment
		(start 261.762748 -286.981646)
		(end 261.327646 -287.416748)
		(width 0.20066)
		(layer "F.Cu")
		(net "M_D_CPU0_SA_DQ<26>")
	)
	(segment
		(start 267.724382 -287.416748)
		(end 266.409678 -287.416748)
		(width 0.20066)
		(layer "F.Cu")
		(net "M_D_CPU0_SA_DQ<26>")
	)
	(segment
		(start 265.458194 -286.991806)
		(end 264.825226 -286.991806)
		(width 0.20066)
		(layer "F.Cu")
		(net "M_D_CPU0_SA_DQ<26>")
	)
	(segment
		(start 347.942916 -268.84757)
		(end 347.942662 -268.847824)
		(width 0.20066)
		(layer "F.Cu")
		(net "M_D_CPU0_SA_DQ<26>")
	)
	(segment
		(start 266.197842 -287.628584)
		(end 265.769344 -287.628584)
		(width 0.20066)
		(layer "F.Cu")
		(net "M_D_CPU0_SA_DQ<26>")
	)
	(segment
		(start 262.51027 -286.991806)
		(end 262.50011 -286.981646)
		(width 0.101854)
		(layer "F.Cu")
		(net "M_D_CPU0_SA_DQ<26>")
	)
	(segment
		(start 262.50011 -286.981646)
		(end 261.762748 -286.981646)
		(width 0.20066)
		(layer "F.Cu")
		(net "M_D_CPU0_SA_DQ<26>")
	)
	(segment
		(start 265.601958 -287.461198)
		(end 265.601958 -287.13557)
		(width 0.20066)
		(layer "F.Cu")
		(net "M_D_CPU0_SA_DQ<26>")
	)
	(segment
		(start 265.601958 -287.13557)
		(end 265.458194 -286.991806)
		(width 0.20066)
		(layer "F.Cu")
		(net "M_D_CPU0_SA_DQ<26>")
	)
	(segment
		(start 262.765286 -286.991806)
		(end 262.51027 -286.991806)
		(width 0.101854)
		(layer "F.Cu")
		(net "M_D_CPU0_SA_DQ<26>")
	)
	(segment
		(start 288.31667 -286.958024)
		(end 288.12363 -287.151064)
		(width 0.18288)
		(layer "In11.Cu")
		(net "M_D_CPU0_SA_DQ<26>")
	)
	(segment
		(start 326.764142 -271.437354)
		(end 314.741306 -283.46019)
		(width 0.18288)
		(layer "In11.Cu")
		(net "M_D_CPU0_SA_DQ<26>")
	)
	(segment
		(start 299.658278 -287.91281)
		(end 299.588174 -287.842706)
		(width 0.18288)
		(layer "In11.Cu")
		(net "M_D_CPU0_SA_DQ<26>")
	)
	(segment
		(start 343.056464 -269.707868)
		(end 343.041732 -269.699232)
		(width 0.088646)
		(layer "In11.Cu")
		(net "M_D_CPU0_SA_DQ<26>")
	)
	(segment
		(start 339.297518 -269.707868)
		(end 339.287104 -269.701772)
		(width 0.088646)
		(layer "In11.Cu")
		(net "M_D_CPU0_SA_DQ<26>")
	)
	(segment
		(start 290.87191 -287.921954)
		(end 290.609782 -287.659826)
		(width 0.18288)
		(layer "In11.Cu")
		(net "M_D_CPU0_SA_DQ<26>")
	)
	(segment
		(start 305.50231 -285.36011)
		(end 304.815494 -286.046926)
		(width 0.18288)
		(layer "In11.Cu")
		(net "M_D_CPU0_SA_DQ<26>")
	)
	(segment
		(start 277.358094 -288.498026)
		(end 277.078694 -288.777426)
		(width 0.18288)
		(layer "In11.Cu")
		(net "M_D_CPU0_SA_DQ<26>")
	)
	(segment
		(start 298.079414 -287.842706)
		(end 297.341544 -288.580576)
		(width 0.18288)
		(layer "In11.Cu")
		(net "M_D_CPU0_SA_DQ<26>")
	)
	(segment
		(start 289.52571 -287.151064)
		(end 289.52571 -287.466786)
		(width 0.18288)
		(layer "In11.Cu")
		(net "M_D_CPU0_SA_DQ<26>")
	)
	(segment
		(start 304.815494 -286.046926)
		(end 302.846994 -286.046926)
		(width 0.18288)
		(layer "In11.Cu")
		(net "M_D_CPU0_SA_DQ<26>")
	)
	(segment
		(start 341.176864 -269.707868)
		(end 341.162132 -269.699232)
		(width 0.088646)
		(layer "In11.Cu")
		(net "M_D_CPU0_SA_DQ<26>")
	)
	(segment
		(start 299.588174 -287.842706)
		(end 298.079414 -287.842706)
		(width 0.18288)
		(layer "In11.Cu")
		(net "M_D_CPU0_SA_DQ<26>")
	)
	(segment
		(start 285.881572 -287.778952)
		(end 285.688532 -287.971992)
		(width 0.18288)
		(layer "In11.Cu")
		(net "M_D_CPU0_SA_DQ<26>")
	)
	(segment
		(start 307.271166 -284.764226)
		(end 306.675282 -285.36011)
		(width 0.18288)
		(layer "In11.Cu")
		(net "M_D_CPU0_SA_DQ<26>")
	)
	(segment
		(start 290.41979 -287.659826)
		(end 290.22675 -287.466786)
		(width 0.18288)
		(layer "In11.Cu")
		(net "M_D_CPU0_SA_DQ<26>")
	)
	(segment
		(start 314.741306 -283.46019)
		(end 311.74817 -283.46019)
		(width 0.18288)
		(layer "In11.Cu")
		(net "M_D_CPU0_SA_DQ<26>")
	)
	(segment
		(start 288.63163 -286.958024)
		(end 288.31667 -286.958024)
		(width 0.18288)
		(layer "In11.Cu")
		(net "M_D_CPU0_SA_DQ<26>")
	)
	(segment
		(start 269.425674 -287.416748)
		(end 268.829282 -287.416748)
		(width 0.18288)
		(layer "In11.Cu")
		(net "M_D_CPU0_SA_DQ<26>")
	)
	(segment
		(start 345.876118 -269.707868)
		(end 345.865704 -269.701772)
		(width 0.088646)
		(layer "In11.Cu")
		(net "M_D_CPU0_SA_DQ<26>")
	)
	(segment
		(start 332.926944 -269.535656)
		(end 332.54188 -269.535656)
		(width 0.088646)
		(layer "In11.Cu")
		(net "M_D_CPU0_SA_DQ<26>")
	)
	(segment
		(start 274.970494 -287.659826)
		(end 273.141694 -287.659826)
		(width 0.18288)
		(layer "In11.Cu")
		(net "M_D_CPU0_SA_DQ<26>")
	)
	(segment
		(start 290.609782 -287.659826)
		(end 290.41979 -287.659826)
		(width 0.18288)
		(layer "In11.Cu")
		(net "M_D_CPU0_SA_DQ<26>")
	)
	(segment
		(start 279.172416 -288.69259)
		(end 278.977852 -288.498026)
		(width 0.18288)
		(layer "In11.Cu")
		(net "M_D_CPU0_SA_DQ<26>")
	)
	(segment
		(start 292.064694 -288.523426)
		(end 291.810694 -288.777426)
		(width 0.18288)
		(layer "In11.Cu")
		(net "M_D_CPU0_SA_DQ<26>")
	)
	(segment
		(start 347.587824 -269.288514)
		(end 347.15831 -269.04061)
		(width 0.088646)
		(layer "In11.Cu")
		(net "M_D_CPU0_SA_DQ<26>")
	)
	(segment
		(start 269.944088 -287.935162)
		(end 269.425674 -287.416748)
		(width 0.18288)
		(layer "In11.Cu")
		(net "M_D_CPU0_SA_DQ<26>")
	)
	(segment
		(start 339.682328 -269.701772)
		(end 339.671914 -269.707868)
		(width 0.088646)
		(layer "In11.Cu")
		(net "M_D_CPU0_SA_DQ<26>")
	)
	(segment
		(start 297.341544 -288.580576)
		(end 296.743628 -288.828226)
		(width 0.18288)
		(layer "In11.Cu")
		(net "M_D_CPU0_SA_DQ<26>")
	)
	(segment
		(start 284.80385 -287.841182)
		(end 283.171138 -287.841182)
		(width 0.18288)
		(layer "In11.Cu")
		(net "M_D_CPU0_SA_DQ<26>")
	)
	(segment
		(start 291.810694 -288.777426)
		(end 291.093398 -288.777426)
		(width 0.18288)
		(layer "In11.Cu")
		(net "M_D_CPU0_SA_DQ<26>")
	)
	(segment
		(start 294.090852 -288.523426)
		(end 292.064694 -288.523426)
		(width 0.18288)
		(layer "In11.Cu")
		(net "M_D_CPU0_SA_DQ<26>")
	)
	(segment
		(start 286.074612 -287.262062)
		(end 285.881572 -287.455102)
		(width 0.18288)
		(layer "In11.Cu")
		(net "M_D_CPU0_SA_DQ<26>")
	)
	(segment
		(start 300.98111 -287.91281)
		(end 299.658278 -287.91281)
		(width 0.18288)
		(layer "In11.Cu")
		(net "M_D_CPU0_SA_DQ<26>")
	)
	(segment
		(start 333.149956 -269.758668)
		(end 332.926944 -269.535656)
		(width 0.088646)
		(layer "In11.Cu")
		(net "M_D_CPU0_SA_DQ<26>")
	)
	(segment
		(start 290.87191 -288.555938)
		(end 290.87191 -287.921954)
		(width 0.18288)
		(layer "In11.Cu")
		(net "M_D_CPU0_SA_DQ<26>")
	)
	(segment
		(start 295.392094 -288.828226)
		(end 295.256458 -288.69259)
		(width 0.18288)
		(layer "In11.Cu")
		(net "M_D_CPU0_SA_DQ<26>")
	)
	(segment
		(start 290.22675 -287.151064)
		(end 290.03371 -286.958024)
		(width 0.18288)
		(layer "In11.Cu")
		(net "M_D_CPU0_SA_DQ<26>")
	)
	(segment
		(start 347.942662 -269.38351)
		(end 347.587824 -269.288514)
		(width 0.088646)
		(layer "In11.Cu")
		(net "M_D_CPU0_SA_DQ<26>")
	)
	(segment
		(start 309.93969 -284.764226)
		(end 307.271166 -284.764226)
		(width 0.18288)
		(layer "In11.Cu")
		(net "M_D_CPU0_SA_DQ<26>")
	)
	(segment
		(start 346.573094 -269.117826)
		(end 346.527882 -269.163038)
		(width 0.088646)
		(layer "In11.Cu")
		(net "M_D_CPU0_SA_DQ<26>")
	)
	(segment
		(start 302.846994 -286.046926)
		(end 300.98111 -287.91281)
		(width 0.18288)
		(layer "In11.Cu")
		(net "M_D_CPU0_SA_DQ<26>")
	)
	(segment
		(start 289.01771 -287.659826)
		(end 288.82467 -287.466786)
		(width 0.18288)
		(layer "In11.Cu")
		(net "M_D_CPU0_SA_DQ<26>")
	)
	(segment
		(start 272.866358 -287.935162)
		(end 269.944088 -287.935162)
		(width 0.18288)
		(layer "In11.Cu")
		(net "M_D_CPU0_SA_DQ<26>")
	)
	(segment
		(start 284.93466 -287.971992)
		(end 284.80385 -287.841182)
		(width 0.18288)
		(layer "In11.Cu")
		(net "M_D_CPU0_SA_DQ<26>")
	)
	(segment
		(start 332.314804 -270.29791)
		(end 331.17536 -271.437354)
		(width 0.088646)
		(layer "In11.Cu")
		(net "M_D_CPU0_SA_DQ<26>")
	)
	(segment
		(start 276.088094 -288.777426)
		(end 274.970494 -287.659826)
		(width 0.18288)
		(layer "In11.Cu")
		(net "M_D_CPU0_SA_DQ<26>")
	)
	(segment
		(start 294.260016 -288.69259)
		(end 294.090852 -288.523426)
		(width 0.18288)
		(layer "In11.Cu")
		(net "M_D_CPU0_SA_DQ<26>")
	)
	(segment
		(start 310.80075 -284.40761)
		(end 309.93969 -284.764226)
		(width 0.18288)
		(layer "In11.Cu")
		(net "M_D_CPU0_SA_DQ<26>")
	)
	(segment
		(start 296.743628 -288.828226)
		(end 295.392094 -288.828226)
		(width 0.18288)
		(layer "In11.Cu")
		(net "M_D_CPU0_SA_DQ<26>")
	)
	(segment
		(start 286.389572 -287.262062)
		(end 286.074612 -287.262062)
		(width 0.18288)
		(layer "In11.Cu")
		(net "M_D_CPU0_SA_DQ<26>")
	)
	(segment
		(start 291.093398 -288.777426)
		(end 290.87191 -288.555938)
		(width 0.18288)
		(layer "In11.Cu")
		(net "M_D_CPU0_SA_DQ<26>")
	)
	(segment
		(start 331.004672 -271.437354)
		(end 326.764142 -271.437354)
		(width 0.18288)
		(layer "In11.Cu")
		(net "M_D_CPU0_SA_DQ<26>")
	)
	(segment
		(start 289.52571 -287.466786)
		(end 289.33267 -287.659826)
		(width 0.18288)
		(layer "In11.Cu")
		(net "M_D_CPU0_SA_DQ<26>")
	)
	(segment
		(start 282.184094 -288.828226)
		(end 280.708862 -288.828226)
		(width 0.18288)
		(layer "In11.Cu")
		(net "M_D_CPU0_SA_DQ<26>")
	)
	(segment
		(start 343.996264 -269.707868)
		(end 343.981532 -269.699232)
		(width 0.088646)
		(layer "In11.Cu")
		(net "M_D_CPU0_SA_DQ<26>")
	)
	(segment
		(start 289.71875 -286.958024)
		(end 289.52571 -287.151064)
		(width 0.18288)
		(layer "In11.Cu")
		(net "M_D_CPU0_SA_DQ<26>")
	)
	(segment
		(start 342.116664 -269.707868)
		(end 342.101932 -269.699232)
		(width 0.088646)
		(layer "In11.Cu")
		(net "M_D_CPU0_SA_DQ<26>")
	)
	(segment
		(start 280.708862 -288.828226)
		(end 280.573226 -288.69259)
		(width 0.18288)
		(layer "In11.Cu")
		(net "M_D_CPU0_SA_DQ<26>")
	)
	(segment
		(start 290.03371 -286.958024)
		(end 289.71875 -286.958024)
		(width 0.18288)
		(layer "In11.Cu")
		(net "M_D_CPU0_SA_DQ<26>")
	)
	(segment
		(start 273.141694 -287.659826)
		(end 272.866358 -287.935162)
		(width 0.18288)
		(layer "In11.Cu")
		(net "M_D_CPU0_SA_DQ<26>")
	)
	(segment
		(start 280.573226 -288.69259)
		(end 279.172416 -288.69259)
		(width 0.18288)
		(layer "In11.Cu")
		(net "M_D_CPU0_SA_DQ<26>")
	)
	(segment
		(start 311.74817 -283.46019)
		(end 310.80075 -284.40761)
		(width 0.18288)
		(layer "In11.Cu")
		(net "M_D_CPU0_SA_DQ<26>")
	)
	(segment
		(start 306.675282 -285.36011)
		(end 305.50231 -285.36011)
		(width 0.18288)
		(layer "In11.Cu")
		(net "M_D_CPU0_SA_DQ<26>")
	)
	(segment
		(start 288.82467 -287.151064)
		(end 288.63163 -286.958024)
		(width 0.18288)
		(layer "In11.Cu")
		(net "M_D_CPU0_SA_DQ<26>")
	)
	(segment
		(start 286.775652 -287.971992)
		(end 286.582612 -287.778952)
		(width 0.18288)
		(layer "In11.Cu")
		(net "M_D_CPU0_SA_DQ<26>")
	)
	(segment
		(start 278.977852 -288.498026)
		(end 277.358094 -288.498026)
		(width 0.18288)
		(layer "In11.Cu")
		(net "M_D_CPU0_SA_DQ<26>")
	)
	(segment
		(start 283.171138 -287.841182)
		(end 282.184094 -288.828226)
		(width 0.18288)
		(layer "In11.Cu")
		(net "M_D_CPU0_SA_DQ<26>")
	)
	(segment
		(start 331.17536 -271.437354)
		(end 331.004672 -271.437354)
		(width 0.088646)
		(layer "In11.Cu")
		(net "M_D_CPU0_SA_DQ<26>")
	)
	(segment
		(start 285.688532 -287.971992)
		(end 284.93466 -287.971992)
		(width 0.18288)
		(layer "In11.Cu")
		(net "M_D_CPU0_SA_DQ<26>")
	)
	(segment
		(start 288.12363 -287.466786)
		(end 287.618424 -287.971992)
		(width 0.18288)
		(layer "In11.Cu")
		(net "M_D_CPU0_SA_DQ<26>")
	)
	(segment
		(start 295.256458 -288.69259)
		(end 294.260016 -288.69259)
		(width 0.18288)
		(layer "In11.Cu")
		(net "M_D_CPU0_SA_DQ<26>")
	)
	(segment
		(start 289.33267 -287.659826)
		(end 289.01771 -287.659826)
		(width 0.18288)
		(layer "In11.Cu")
		(net "M_D_CPU0_SA_DQ<26>")
	)
	(segment
		(start 288.82467 -287.466786)
		(end 288.82467 -287.151064)
		(width 0.18288)
		(layer "In11.Cu")
		(net "M_D_CPU0_SA_DQ<26>")
	)
	(segment
		(start 344.936064 -269.707868)
		(end 344.921332 -269.699232)
		(width 0.088646)
		(layer "In11.Cu")
		(net "M_D_CPU0_SA_DQ<26>")
	)
	(segment
		(start 332.54188 -269.535656)
		(end 332.314804 -269.762732)
		(width 0.088646)
		(layer "In11.Cu")
		(net "M_D_CPU0_SA_DQ<26>")
	)
	(segment
		(start 287.618424 -287.971992)
		(end 286.775652 -287.971992)
		(width 0.18288)
		(layer "In11.Cu")
		(net "M_D_CPU0_SA_DQ<26>")
	)
	(segment
		(start 332.314804 -269.762732)
		(end 332.314804 -270.29791)
		(width 0.088646)
		(layer "In11.Cu")
		(net "M_D_CPU0_SA_DQ<26>")
	)
	(segment
		(start 286.582612 -287.778952)
		(end 286.582612 -287.455102)
		(width 0.18288)
		(layer "In11.Cu")
		(net "M_D_CPU0_SA_DQ<26>")
	)
	(segment
		(start 288.12363 -287.151064)
		(end 288.12363 -287.466786)
		(width 0.18288)
		(layer "In11.Cu")
		(net "M_D_CPU0_SA_DQ<26>")
	)
	(segment
		(start 290.22675 -287.466786)
		(end 290.22675 -287.151064)
		(width 0.18288)
		(layer "In11.Cu")
		(net "M_D_CPU0_SA_DQ<26>")
	)
	(segment
		(start 285.881572 -287.455102)
		(end 285.881572 -287.778952)
		(width 0.18288)
		(layer "In11.Cu")
		(net "M_D_CPU0_SA_DQ<26>")
	)
	(segment
		(start 277.078694 -288.777426)
		(end 276.088094 -288.777426)
		(width 0.18288)
		(layer "In11.Cu")
		(net "M_D_CPU0_SA_DQ<26>")
	)
	(segment
		(start 346.46997 -269.269972)
		(end 346.429838 -269.460726)
		(width 0.088646)
		(layer "In11.Cu")
		(net "M_D_CPU0_SA_DQ<26>")
	)
	(segment
		(start 286.582612 -287.455102)
		(end 286.389572 -287.262062)
		(width 0.18288)
		(layer "In11.Cu")
		(net "M_D_CPU0_SA_DQ<26>")
	)
	(segment
		(start 333.845662 -269.758668)
		(end 333.149956 -269.758668)
		(width 0.088646)
		(layer "In11.Cu")
		(net "M_D_CPU0_SA_DQ<26>")
	)
	(arc
		(start 344.921332 -269.699232)
		(mid 344.644891 -269.632066)
		(end 344.37066 -269.707868)
		(width 0.088646)
		(layer "In11.Cu")
		(net "M_D_CPU0_SA_DQ<26>")
	)
	(arc
		(start 346.527882 -269.163038)
		(mid 346.491142 -269.21229)
		(end 346.46997 -269.269972)
		(width 0.088646)
		(layer "In11.Cu")
		(net "M_D_CPU0_SA_DQ<26>")
	)
	(arc
		(start 340.61146 -269.707868)
		(mid 340.424262 -269.758011)
		(end 340.237064 -269.707868)
		(width 0.088646)
		(layer "In11.Cu")
		(net "M_D_CPU0_SA_DQ<26>")
	)
	(arc
		(start 337.417664 -269.707868)
		(mid 337.134962 -269.632126)
		(end 336.85226 -269.707868)
		(width 0.088646)
		(layer "In11.Cu")
		(net "M_D_CPU0_SA_DQ<26>")
	)
	(arc
		(start 346.429838 -269.460726)
		(mid 346.369969 -269.598602)
		(end 346.260674 -269.701772)
		(width 0.088646)
		(layer "In11.Cu")
		(net "M_D_CPU0_SA_DQ<26>")
	)
	(arc
		(start 334.598264 -269.707868)
		(mid 334.315562 -269.632126)
		(end 334.03286 -269.707868)
		(width 0.088646)
		(layer "In11.Cu")
		(net "M_D_CPU0_SA_DQ<26>")
	)
	(arc
		(start 338.357464 -269.707868)
		(mid 338.074762 -269.632126)
		(end 337.79206 -269.707868)
		(width 0.088646)
		(layer "In11.Cu")
		(net "M_D_CPU0_SA_DQ<26>")
	)
	(arc
		(start 335.91246 -269.707868)
		(mid 335.725262 -269.758011)
		(end 335.538064 -269.707868)
		(width 0.088646)
		(layer "In11.Cu")
		(net "M_D_CPU0_SA_DQ<26>")
	)
	(arc
		(start 336.85226 -269.707868)
		(mid 336.665062 -269.758011)
		(end 336.477864 -269.707868)
		(width 0.088646)
		(layer "In11.Cu")
		(net "M_D_CPU0_SA_DQ<26>")
	)
	(arc
		(start 343.041732 -269.699232)
		(mid 342.765291 -269.632066)
		(end 342.49106 -269.707868)
		(width 0.088646)
		(layer "In11.Cu")
		(net "M_D_CPU0_SA_DQ<26>")
	)
	(arc
		(start 334.03286 -269.707868)
		(mid 333.942604 -269.74559)
		(end 333.845662 -269.758668)
		(width 0.088646)
		(layer "In11.Cu")
		(net "M_D_CPU0_SA_DQ<26>")
	)
	(arc
		(start 346.260674 -269.701772)
		(mid 346.255633 -269.704885)
		(end 346.250514 -269.707868)
		(width 0.088646)
		(layer "In11.Cu")
		(net "M_D_CPU0_SA_DQ<26>")
	)
	(arc
		(start 340.237064 -269.707868)
		(mid 339.960505 -269.632159)
		(end 339.682328 -269.701772)
		(width 0.088646)
		(layer "In11.Cu")
		(net "M_D_CPU0_SA_DQ<26>")
	)
	(arc
		(start 337.79206 -269.707868)
		(mid 337.604862 -269.758011)
		(end 337.417664 -269.707868)
		(width 0.088646)
		(layer "In11.Cu")
		(net "M_D_CPU0_SA_DQ<26>")
	)
	(arc
		(start 343.43086 -269.707868)
		(mid 343.243662 -269.758011)
		(end 343.056464 -269.707868)
		(width 0.088646)
		(layer "In11.Cu")
		(net "M_D_CPU0_SA_DQ<26>")
	)
	(arc
		(start 342.101932 -269.699232)
		(mid 341.825491 -269.632066)
		(end 341.55126 -269.707868)
		(width 0.088646)
		(layer "In11.Cu")
		(net "M_D_CPU0_SA_DQ<26>")
	)
	(arc
		(start 345.865704 -269.701772)
		(mid 345.587272 -269.631958)
		(end 345.31046 -269.707868)
		(width 0.088646)
		(layer "In11.Cu")
		(net "M_D_CPU0_SA_DQ<26>")
	)
	(arc
		(start 343.981532 -269.699232)
		(mid 343.705091 -269.632066)
		(end 343.43086 -269.707868)
		(width 0.088646)
		(layer "In11.Cu")
		(net "M_D_CPU0_SA_DQ<26>")
	)
	(arc
		(start 341.55126 -269.707868)
		(mid 341.364062 -269.758011)
		(end 341.176864 -269.707868)
		(width 0.088646)
		(layer "In11.Cu")
		(net "M_D_CPU0_SA_DQ<26>")
	)
	(arc
		(start 341.162132 -269.699232)
		(mid 340.885691 -269.632066)
		(end 340.61146 -269.707868)
		(width 0.088646)
		(layer "In11.Cu")
		(net "M_D_CPU0_SA_DQ<26>")
	)
	(arc
		(start 342.49106 -269.707868)
		(mid 342.303862 -269.758011)
		(end 342.116664 -269.707868)
		(width 0.088646)
		(layer "In11.Cu")
		(net "M_D_CPU0_SA_DQ<26>")
	)
	(arc
		(start 347.15831 -269.04061)
		(mid 346.852588 -268.979899)
		(end 346.573094 -269.117826)
		(width 0.088646)
		(layer "In11.Cu")
		(net "M_D_CPU0_SA_DQ<26>")
	)
	(arc
		(start 334.97266 -269.707868)
		(mid 334.785462 -269.758011)
		(end 334.598264 -269.707868)
		(width 0.088646)
		(layer "In11.Cu")
		(net "M_D_CPU0_SA_DQ<26>")
	)
	(arc
		(start 335.538064 -269.707868)
		(mid 335.255362 -269.632126)
		(end 334.97266 -269.707868)
		(width 0.088646)
		(layer "In11.Cu")
		(net "M_D_CPU0_SA_DQ<26>")
	)
	(arc
		(start 345.31046 -269.707868)
		(mid 345.123262 -269.758011)
		(end 344.936064 -269.707868)
		(width 0.088646)
		(layer "In11.Cu")
		(net "M_D_CPU0_SA_DQ<26>")
	)
	(arc
		(start 339.287104 -269.701772)
		(mid 339.008672 -269.631958)
		(end 338.73186 -269.707868)
		(width 0.088646)
		(layer "In11.Cu")
		(net "M_D_CPU0_SA_DQ<26>")
	)
	(arc
		(start 339.671914 -269.707868)
		(mid 339.484716 -269.758011)
		(end 339.297518 -269.707868)
		(width 0.088646)
		(layer "In11.Cu")
		(net "M_D_CPU0_SA_DQ<26>")
	)
	(arc
		(start 346.250514 -269.707868)
		(mid 346.063316 -269.758011)
		(end 345.876118 -269.707868)
		(width 0.088646)
		(layer "In11.Cu")
		(net "M_D_CPU0_SA_DQ<26>")
	)
	(arc
		(start 336.477864 -269.707868)
		(mid 336.195162 -269.632126)
		(end 335.91246 -269.707868)
		(width 0.088646)
		(layer "In11.Cu")
		(net "M_D_CPU0_SA_DQ<26>")
	)
	(arc
		(start 344.37066 -269.707868)
		(mid 344.183462 -269.758011)
		(end 343.996264 -269.707868)
		(width 0.088646)
		(layer "In11.Cu")
		(net "M_D_CPU0_SA_DQ<26>")
	)
	(arc
		(start 338.73186 -269.707868)
		(mid 338.544662 -269.758011)
		(end 338.357464 -269.707868)
		(width 0.088646)
		(layer "In11.Cu")
		(net "M_D_CPU0_SA_DQ<26>")
	)
	(segment
		(start 258.28498 -286.623506)
		(end 258.130548 -286.777938)
		(width 0.20066)
		(layer "F.Cu")
		(net "M_D_CPU0_SA_DQ<25>")
	)
	(segment
		(start 261.984998 -286.56661)
		(end 261.560056 -286.141668)
		(width 0.20066)
		(layer "F.Cu")
		(net "M_D_CPU0_SA_DQ<25>")
	)
	(segment
		(start 346.532962 -268.033754)
		(end 346.533216 -268.034008)
		(width 0.20066)
		(layer "F.Cu")
		(net "M_D_CPU0_SA_DQ<25>")
	)
	(segment
		(start 258.130548 -286.777938)
		(end 257.626104 -286.777938)
		(width 0.20066)
		(layer "F.Cu")
		(net "M_D_CPU0_SA_DQ<25>")
	)
	(segment
		(start 258.44754 -286.132778)
		(end 258.28498 -286.295338)
		(width 0.20066)
		(layer "F.Cu")
		(net "M_D_CPU0_SA_DQ<25>")
	)
	(segment
		(start 259.056378 -286.132778)
		(end 258.44754 -286.132778)
		(width 0.20066)
		(layer "F.Cu")
		(net "M_D_CPU0_SA_DQ<25>")
	)
	(segment
		(start 263.624314 -286.56661)
		(end 261.984998 -286.56661)
		(width 0.20066)
		(layer "F.Cu")
		(net "M_D_CPU0_SA_DQ<25>")
	)
	(segment
		(start 257.626104 -286.777938)
		(end 257.414776 -286.56661)
		(width 0.20066)
		(layer "F.Cu")
		(net "M_D_CPU0_SA_DQ<25>")
	)
	(segment
		(start 346.533216 -268.034008)
		(end 346.533216 -268.569694)
		(width 0.20066)
		(layer "F.Cu")
		(net "M_D_CPU0_SA_DQ<25>")
	)
	(segment
		(start 258.28498 -286.295338)
		(end 258.28498 -286.623506)
		(width 0.20066)
		(layer "F.Cu")
		(net "M_D_CPU0_SA_DQ<25>")
	)
	(segment
		(start 257.414776 -286.56661)
		(end 256.080514 -286.56661)
		(width 0.20066)
		(layer "F.Cu")
		(net "M_D_CPU0_SA_DQ<25>")
	)
	(segment
		(start 261.381494 -286.141668)
		(end 261.050786 -286.141668)
		(width 0.101854)
		(layer "F.Cu")
		(net "M_D_CPU0_SA_DQ<25>")
	)
	(segment
		(start 261.050786 -286.141668)
		(end 259.065268 -286.141668)
		(width 0.1016)
		(layer "F.Cu")
		(net "M_D_CPU0_SA_DQ<25>")
	)
	(segment
		(start 259.065268 -286.141668)
		(end 259.056378 -286.132778)
		(width 0.1016)
		(layer "F.Cu")
		(net "M_D_CPU0_SA_DQ<25>")
	)
	(segment
		(start 264.729214 -286.56661)
		(end 263.624314 -286.56661)
		(width 0.20066)
		(layer "F.Cu")
		(net "M_D_CPU0_SA_DQ<25>")
	)
	(segment
		(start 261.560056 -286.141668)
		(end 261.381494 -286.141668)
		(width 0.20066)
		(layer "F.Cu")
		(net "M_D_CPU0_SA_DQ<25>")
	)
	(segment
		(start 287.75025 -286.745426)
		(end 287.348676 -286.745426)
		(width 0.18288)
		(layer "In11.Cu")
		(net "M_D_CPU0_SA_DQ<25>")
	)
	(segment
		(start 341.176864 -269.059152)
		(end 341.162132 -269.067788)
		(width 0.088646)
		(layer "In11.Cu")
		(net "M_D_CPU0_SA_DQ<25>")
	)
	(segment
		(start 285.384494 -286.948626)
		(end 284.539436 -286.948626)
		(width 0.18288)
		(layer "In11.Cu")
		(net "M_D_CPU0_SA_DQ<25>")
	)
	(segment
		(start 286.261556 -286.745426)
		(end 285.587694 -286.745426)
		(width 0.18288)
		(layer "In11.Cu")
		(net "M_D_CPU0_SA_DQ<25>")
	)
	(segment
		(start 276.265894 -287.101026)
		(end 273.624294 -287.101026)
		(width 0.18288)
		(layer "In11.Cu")
		(net "M_D_CPU0_SA_DQ<25>")
	)
	(segment
		(start 280.863548 -287.634426)
		(end 280.655522 -287.842452)
		(width 0.18288)
		(layer "In11.Cu")
		(net "M_D_CPU0_SA_DQ<25>")
	)
	(segment
		(start 305.067208 -284.480254)
		(end 305.067208 -284.97022)
		(width 0.18288)
		(layer "In11.Cu")
		(net "M_D_CPU0_SA_DQ<25>")
	)
	(segment
		(start 267.066776 -286.991298)
		(end 266.855448 -287.202626)
		(width 0.18288)
		(layer "In11.Cu")
		(net "M_D_CPU0_SA_DQ<25>")
	)
	(segment
		(start 343.436956 -269.062708)
		(end 343.431114 -269.059152)
		(width 0.088646)
		(layer "In11.Cu")
		(net "M_D_CPU0_SA_DQ<25>")
	)
	(segment
		(start 314.55106 -282.92679)
		(end 311.55767 -282.92679)
		(width 0.18288)
		(layer "In11.Cu")
		(net "M_D_CPU0_SA_DQ<25>")
	)
	(segment
		(start 301.665894 -285.485586)
		(end 301.665894 -286.062674)
		(width 0.18288)
		(layer "In11.Cu")
		(net "M_D_CPU0_SA_DQ<25>")
	)
	(segment
		(start 298.091098 -286.992568)
		(end 297.50004 -287.583626)
		(width 0.18288)
		(layer "In11.Cu")
		(net "M_D_CPU0_SA_DQ<25>")
	)
	(segment
		(start 331.241654 -270.929354)
		(end 330.903072 -270.929354)
		(width 0.088646)
		(layer "In11.Cu")
		(net "M_D_CPU0_SA_DQ<25>")
	)
	(segment
		(start 266.855448 -287.202626)
		(end 265.8999 -287.202626)
		(width 0.18288)
		(layer "In11.Cu")
		(net "M_D_CPU0_SA_DQ<25>")
	)
	(segment
		(start 332.074774 -269.496032)
		(end 332.074774 -270.096234)
		(width 0.088646)
		(layer "In11.Cu")
		(net "M_D_CPU0_SA_DQ<25>")
	)
	(segment
		(start 303.342294 -285.373826)
		(end 303.164494 -285.196026)
		(width 0.18288)
		(layer "In11.Cu")
		(net "M_D_CPU0_SA_DQ<25>")
	)
	(segment
		(start 290.161726 -286.085026)
		(end 288.41065 -286.085026)
		(width 0.18288)
		(layer "In11.Cu")
		(net "M_D_CPU0_SA_DQ<25>")
	)
	(segment
		(start 332.435962 -269.134844)
		(end 332.074774 -269.496032)
		(width 0.088646)
		(layer "In11.Cu")
		(net "M_D_CPU0_SA_DQ<25>")
	)
	(segment
		(start 291.759894 -287.380426)
		(end 291.457126 -287.380426)
		(width 0.18288)
		(layer "In11.Cu")
		(net "M_D_CPU0_SA_DQ<25>")
	)
	(segment
		(start 269.30477 -286.888936)
		(end 269.202408 -286.991298)
		(width 0.18288)
		(layer "In11.Cu")
		(net "M_D_CPU0_SA_DQ<25>")
	)
	(segment
		(start 311.55767 -282.92679)
		(end 310.50992 -283.97454)
		(width 0.18288)
		(layer "In11.Cu")
		(net "M_D_CPU0_SA_DQ<25>")
	)
	(segment
		(start 286.454596 -286.265874)
		(end 286.454596 -286.552386)
		(width 0.18288)
		(layer "In11.Cu")
		(net "M_D_CPU0_SA_DQ<25>")
	)
	(segment
		(start 300.805342 -286.923226)
		(end 299.652436 -286.923226)
		(width 0.18288)
		(layer "In11.Cu")
		(net "M_D_CPU0_SA_DQ<25>")
	)
	(segment
		(start 341.551514 -269.059152)
		(end 341.545672 -269.05585)
		(width 0.088646)
		(layer "In11.Cu")
		(net "M_D_CPU0_SA_DQ<25>")
	)
	(segment
		(start 277.120858 -287.95599)
		(end 276.265894 -287.101026)
		(width 0.18288)
		(layer "In11.Cu")
		(net "M_D_CPU0_SA_DQ<25>")
	)
	(segment
		(start 345.955874 -269.012924)
		(end 345.875864 -269.059152)
		(width 0.088646)
		(layer "In11.Cu")
		(net "M_D_CPU0_SA_DQ<25>")
	)
	(segment
		(start 310.50992 -283.97454)
		(end 309.829708 -284.256226)
		(width 0.18288)
		(layer "In11.Cu")
		(net "M_D_CPU0_SA_DQ<25>")
	)
	(segment
		(start 291.457126 -287.380426)
		(end 290.161726 -286.085026)
		(width 0.18288)
		(layer "In11.Cu")
		(net "M_D_CPU0_SA_DQ<25>")
	)
	(segment
		(start 284.539436 -286.948626)
		(end 284.495494 -286.992568)
		(width 0.18288)
		(layer "In11.Cu")
		(net "M_D_CPU0_SA_DQ<25>")
	)
	(segment
		(start 345.310714 -269.059152)
		(end 345.304872 -269.05585)
		(width 0.088646)
		(layer "In11.Cu")
		(net "M_D_CPU0_SA_DQ<25>")
	)
	(segment
		(start 265.8999 -287.202626)
		(end 265.263884 -286.56661)
		(width 0.18288)
		(layer "In11.Cu")
		(net "M_D_CPU0_SA_DQ<25>")
	)
	(segment
		(start 301.665894 -286.062674)
		(end 300.805342 -286.923226)
		(width 0.18288)
		(layer "In11.Cu")
		(net "M_D_CPU0_SA_DQ<25>")
	)
	(segment
		(start 304.663602 -285.373826)
		(end 303.342294 -285.373826)
		(width 0.18288)
		(layer "In11.Cu")
		(net "M_D_CPU0_SA_DQ<25>")
	)
	(segment
		(start 284.495494 -286.992568)
		(end 283.130752 -286.992568)
		(width 0.18288)
		(layer "In11.Cu")
		(net "M_D_CPU0_SA_DQ<25>")
	)
	(segment
		(start 273.624294 -287.101026)
		(end 273.412204 -286.888936)
		(width 0.18288)
		(layer "In11.Cu")
		(net "M_D_CPU0_SA_DQ<25>")
	)
	(segment
		(start 287.155636 -286.552386)
		(end 287.155636 -286.265874)
		(width 0.18288)
		(layer "In11.Cu")
		(net "M_D_CPU0_SA_DQ<25>")
	)
	(segment
		(start 265.263884 -286.56661)
		(end 264.729214 -286.56661)
		(width 0.18288)
		(layer "In11.Cu")
		(net "M_D_CPU0_SA_DQ<25>")
	)
	(segment
		(start 280.655522 -287.842452)
		(end 278.445468 -287.842452)
		(width 0.18288)
		(layer "In11.Cu")
		(net "M_D_CPU0_SA_DQ<25>")
	)
	(segment
		(start 295.950894 -287.583626)
		(end 295.692068 -287.842452)
		(width 0.18288)
		(layer "In11.Cu")
		(net "M_D_CPU0_SA_DQ<25>")
	)
	(segment
		(start 287.155636 -286.265874)
		(end 286.962596 -286.072834)
		(width 0.18288)
		(layer "In11.Cu")
		(net "M_D_CPU0_SA_DQ<25>")
	)
	(segment
		(start 341.557356 -269.062708)
		(end 341.551514 -269.059152)
		(width 0.088646)
		(layer "In11.Cu")
		(net "M_D_CPU0_SA_DQ<25>")
	)
	(segment
		(start 342.497156 -269.062708)
		(end 342.491314 -269.059152)
		(width 0.088646)
		(layer "In11.Cu")
		(net "M_D_CPU0_SA_DQ<25>")
	)
	(segment
		(start 305.067208 -284.97022)
		(end 304.663602 -285.373826)
		(width 0.18288)
		(layer "In11.Cu")
		(net "M_D_CPU0_SA_DQ<25>")
	)
	(segment
		(start 293.990268 -287.842452)
		(end 293.817294 -288.015426)
		(width 0.18288)
		(layer "In11.Cu")
		(net "M_D_CPU0_SA_DQ<25>")
	)
	(segment
		(start 343.431114 -269.059152)
		(end 343.425272 -269.05585)
		(width 0.088646)
		(layer "In11.Cu")
		(net "M_D_CPU0_SA_DQ<25>")
	)
	(segment
		(start 282.488894 -287.634426)
		(end 280.863548 -287.634426)
		(width 0.18288)
		(layer "In11.Cu")
		(net "M_D_CPU0_SA_DQ<25>")
	)
	(segment
		(start 286.962596 -286.072834)
		(end 286.647636 -286.072834)
		(width 0.18288)
		(layer "In11.Cu")
		(net "M_D_CPU0_SA_DQ<25>")
	)
	(segment
		(start 283.130752 -286.992568)
		(end 282.488894 -287.634426)
		(width 0.18288)
		(layer "In11.Cu")
		(net "M_D_CPU0_SA_DQ<25>")
	)
	(segment
		(start 332.074774 -270.096234)
		(end 331.241654 -270.929354)
		(width 0.088646)
		(layer "In11.Cu")
		(net "M_D_CPU0_SA_DQ<25>")
	)
	(segment
		(start 295.692068 -287.842452)
		(end 293.990268 -287.842452)
		(width 0.18288)
		(layer "In11.Cu")
		(net "M_D_CPU0_SA_DQ<25>")
	)
	(segment
		(start 299.652436 -286.923226)
		(end 299.583094 -286.992568)
		(width 0.18288)
		(layer "In11.Cu")
		(net "M_D_CPU0_SA_DQ<25>")
	)
	(segment
		(start 340.237064 -269.059152)
		(end 340.22665 -269.065248)
		(width 0.088646)
		(layer "In11.Cu")
		(net "M_D_CPU0_SA_DQ<25>")
	)
	(segment
		(start 344.376756 -269.062708)
		(end 344.370914 -269.059152)
		(width 0.088646)
		(layer "In11.Cu")
		(net "M_D_CPU0_SA_DQ<25>")
	)
	(segment
		(start 288.41065 -286.085026)
		(end 287.75025 -286.745426)
		(width 0.18288)
		(layer "In11.Cu")
		(net "M_D_CPU0_SA_DQ<25>")
	)
	(segment
		(start 345.316556 -269.062708)
		(end 345.310714 -269.059152)
		(width 0.088646)
		(layer "In11.Cu")
		(net "M_D_CPU0_SA_DQ<25>")
	)
	(segment
		(start 303.164494 -285.196026)
		(end 301.955454 -285.196026)
		(width 0.18288)
		(layer "In11.Cu")
		(net "M_D_CPU0_SA_DQ<25>")
	)
	(segment
		(start 301.955454 -285.196026)
		(end 301.665894 -285.485586)
		(width 0.18288)
		(layer "In11.Cu")
		(net "M_D_CPU0_SA_DQ<25>")
	)
	(segment
		(start 305.291236 -284.256226)
		(end 305.067208 -284.480254)
		(width 0.18288)
		(layer "In11.Cu")
		(net "M_D_CPU0_SA_DQ<25>")
	)
	(segment
		(start 286.454596 -286.552386)
		(end 286.261556 -286.745426)
		(width 0.18288)
		(layer "In11.Cu")
		(net "M_D_CPU0_SA_DQ<25>")
	)
	(segment
		(start 278.33193 -287.95599)
		(end 277.120858 -287.95599)
		(width 0.18288)
		(layer "In11.Cu")
		(net "M_D_CPU0_SA_DQ<25>")
	)
	(segment
		(start 342.491314 -269.059152)
		(end 342.485472 -269.05585)
		(width 0.088646)
		(layer "In11.Cu")
		(net "M_D_CPU0_SA_DQ<25>")
	)
	(segment
		(start 273.412204 -286.888936)
		(end 269.30477 -286.888936)
		(width 0.18288)
		(layer "In11.Cu")
		(net "M_D_CPU0_SA_DQ<25>")
	)
	(segment
		(start 299.583094 -286.992568)
		(end 298.091098 -286.992568)
		(width 0.18288)
		(layer "In11.Cu")
		(net "M_D_CPU0_SA_DQ<25>")
	)
	(segment
		(start 330.903072 -270.929354)
		(end 326.548496 -270.929354)
		(width 0.18288)
		(layer "In11.Cu")
		(net "M_D_CPU0_SA_DQ<25>")
	)
	(segment
		(start 292.394894 -288.015426)
		(end 291.759894 -287.380426)
		(width 0.18288)
		(layer "In11.Cu")
		(net "M_D_CPU0_SA_DQ<25>")
	)
	(segment
		(start 344.370914 -269.059152)
		(end 344.365072 -269.05585)
		(width 0.088646)
		(layer "In11.Cu")
		(net "M_D_CPU0_SA_DQ<25>")
	)
	(segment
		(start 285.587694 -286.745426)
		(end 285.384494 -286.948626)
		(width 0.18288)
		(layer "In11.Cu")
		(net "M_D_CPU0_SA_DQ<25>")
	)
	(segment
		(start 326.548496 -270.929354)
		(end 314.55106 -282.92679)
		(width 0.18288)
		(layer "In11.Cu")
		(net "M_D_CPU0_SA_DQ<25>")
	)
	(segment
		(start 269.202408 -286.991298)
		(end 267.066776 -286.991298)
		(width 0.18288)
		(layer "In11.Cu")
		(net "M_D_CPU0_SA_DQ<25>")
	)
	(segment
		(start 293.817294 -288.015426)
		(end 292.394894 -288.015426)
		(width 0.18288)
		(layer "In11.Cu")
		(net "M_D_CPU0_SA_DQ<25>")
	)
	(segment
		(start 297.50004 -287.583626)
		(end 295.950894 -287.583626)
		(width 0.18288)
		(layer "In11.Cu")
		(net "M_D_CPU0_SA_DQ<25>")
	)
	(segment
		(start 287.348676 -286.745426)
		(end 287.155636 -286.552386)
		(width 0.18288)
		(layer "In11.Cu")
		(net "M_D_CPU0_SA_DQ<25>")
	)
	(segment
		(start 278.445468 -287.842452)
		(end 278.33193 -287.95599)
		(width 0.18288)
		(layer "In11.Cu")
		(net "M_D_CPU0_SA_DQ<25>")
	)
	(segment
		(start 339.297518 -269.059152)
		(end 339.287104 -269.065248)
		(width 0.088646)
		(layer "In11.Cu")
		(net "M_D_CPU0_SA_DQ<25>")
	)
	(segment
		(start 309.829708 -284.256226)
		(end 305.291236 -284.256226)
		(width 0.18288)
		(layer "In11.Cu")
		(net "M_D_CPU0_SA_DQ<25>")
	)
	(segment
		(start 286.647636 -286.072834)
		(end 286.454596 -286.265874)
		(width 0.18288)
		(layer "In11.Cu")
		(net "M_D_CPU0_SA_DQ<25>")
	)
	(arc
		(start 345.875864 -269.059152)
		(mid 345.59669 -269.134917)
		(end 345.316556 -269.062708)
		(width 0.088646)
		(layer "In11.Cu")
		(net "M_D_CPU0_SA_DQ<25>")
	)
	(arc
		(start 345.304872 -269.05585)
		(mid 345.120017 -269.0089)
		(end 344.936064 -269.059152)
		(width 0.088646)
		(layer "In11.Cu")
		(net "M_D_CPU0_SA_DQ<25>")
	)
	(arc
		(start 344.936064 -269.059152)
		(mid 344.65689 -269.134917)
		(end 344.376756 -269.062708)
		(width 0.088646)
		(layer "In11.Cu")
		(net "M_D_CPU0_SA_DQ<25>")
	)
	(arc
		(start 333.09306 -269.059152)
		(mid 332.905862 -269.009009)
		(end 332.718664 -269.059152)
		(width 0.088646)
		(layer "In11.Cu")
		(net "M_D_CPU0_SA_DQ<25>")
	)
	(arc
		(start 340.61146 -269.059152)
		(mid 340.424262 -269.009009)
		(end 340.237064 -269.059152)
		(width 0.088646)
		(layer "In11.Cu")
		(net "M_D_CPU0_SA_DQ<25>")
	)
	(arc
		(start 339.287104 -269.065248)
		(mid 339.008672 -269.135094)
		(end 338.73186 -269.059152)
		(width 0.088646)
		(layer "In11.Cu")
		(net "M_D_CPU0_SA_DQ<25>")
	)
	(arc
		(start 344.365072 -269.05585)
		(mid 344.180217 -269.0089)
		(end 343.996264 -269.059152)
		(width 0.088646)
		(layer "In11.Cu")
		(net "M_D_CPU0_SA_DQ<25>")
	)
	(arc
		(start 342.485472 -269.05585)
		(mid 342.300617 -269.0089)
		(end 342.116664 -269.059152)
		(width 0.088646)
		(layer "In11.Cu")
		(net "M_D_CPU0_SA_DQ<25>")
	)
	(arc
		(start 343.996264 -269.059152)
		(mid 343.71709 -269.134917)
		(end 343.436956 -269.062708)
		(width 0.088646)
		(layer "In11.Cu")
		(net "M_D_CPU0_SA_DQ<25>")
	)
	(arc
		(start 343.425272 -269.05585)
		(mid 343.240417 -269.0089)
		(end 343.056464 -269.059152)
		(width 0.088646)
		(layer "In11.Cu")
		(net "M_D_CPU0_SA_DQ<25>")
	)
	(arc
		(start 333.658464 -269.059152)
		(mid 333.375762 -269.134928)
		(end 333.09306 -269.059152)
		(width 0.088646)
		(layer "In11.Cu")
		(net "M_D_CPU0_SA_DQ<25>")
	)
	(arc
		(start 346.533216 -268.569694)
		(mid 346.259054 -268.81021)
		(end 345.955874 -269.012924)
		(width 0.088646)
		(layer "In11.Cu")
		(net "M_D_CPU0_SA_DQ<25>")
	)
	(arc
		(start 338.73186 -269.059152)
		(mid 338.544662 -269.009009)
		(end 338.357464 -269.059152)
		(width 0.088646)
		(layer "In11.Cu")
		(net "M_D_CPU0_SA_DQ<25>")
	)
	(arc
		(start 336.85226 -269.059152)
		(mid 336.665062 -269.009009)
		(end 336.477864 -269.059152)
		(width 0.088646)
		(layer "In11.Cu")
		(net "M_D_CPU0_SA_DQ<25>")
	)
	(arc
		(start 341.162132 -269.067788)
		(mid 340.885657 -269.135108)
		(end 340.61146 -269.059152)
		(width 0.088646)
		(layer "In11.Cu")
		(net "M_D_CPU0_SA_DQ<25>")
	)
	(arc
		(start 340.22665 -269.065248)
		(mid 339.948472 -269.134971)
		(end 339.671914 -269.059152)
		(width 0.088646)
		(layer "In11.Cu")
		(net "M_D_CPU0_SA_DQ<25>")
	)
	(arc
		(start 342.116664 -269.059152)
		(mid 341.83749 -269.134917)
		(end 341.557356 -269.062708)
		(width 0.088646)
		(layer "In11.Cu")
		(net "M_D_CPU0_SA_DQ<25>")
	)
	(arc
		(start 341.545672 -269.05585)
		(mid 341.360817 -269.0089)
		(end 341.176864 -269.059152)
		(width 0.088646)
		(layer "In11.Cu")
		(net "M_D_CPU0_SA_DQ<25>")
	)
	(arc
		(start 334.03286 -269.059152)
		(mid 333.845662 -269.009009)
		(end 333.658464 -269.059152)
		(width 0.088646)
		(layer "In11.Cu")
		(net "M_D_CPU0_SA_DQ<25>")
	)
	(arc
		(start 336.477864 -269.059152)
		(mid 336.195162 -269.134928)
		(end 335.91246 -269.059152)
		(width 0.088646)
		(layer "In11.Cu")
		(net "M_D_CPU0_SA_DQ<25>")
	)
	(arc
		(start 339.671914 -269.059152)
		(mid 339.484716 -269.009009)
		(end 339.297518 -269.059152)
		(width 0.088646)
		(layer "In11.Cu")
		(net "M_D_CPU0_SA_DQ<25>")
	)
	(arc
		(start 337.417664 -269.059152)
		(mid 337.134962 -269.134928)
		(end 336.85226 -269.059152)
		(width 0.088646)
		(layer "In11.Cu")
		(net "M_D_CPU0_SA_DQ<25>")
	)
	(arc
		(start 338.357464 -269.059152)
		(mid 338.074762 -269.134928)
		(end 337.79206 -269.059152)
		(width 0.088646)
		(layer "In11.Cu")
		(net "M_D_CPU0_SA_DQ<25>")
	)
	(arc
		(start 332.718664 -269.059152)
		(mid 332.582295 -269.115594)
		(end 332.435962 -269.134844)
		(width 0.088646)
		(layer "In11.Cu")
		(net "M_D_CPU0_SA_DQ<25>")
	)
	(arc
		(start 334.97266 -269.059152)
		(mid 334.785462 -269.009009)
		(end 334.598264 -269.059152)
		(width 0.088646)
		(layer "In11.Cu")
		(net "M_D_CPU0_SA_DQ<25>")
	)
	(arc
		(start 335.538064 -269.059152)
		(mid 335.255362 -269.134928)
		(end 334.97266 -269.059152)
		(width 0.088646)
		(layer "In11.Cu")
		(net "M_D_CPU0_SA_DQ<25>")
	)
	(arc
		(start 334.598264 -269.059152)
		(mid 334.315562 -269.134928)
		(end 334.03286 -269.059152)
		(width 0.088646)
		(layer "In11.Cu")
		(net "M_D_CPU0_SA_DQ<25>")
	)
	(arc
		(start 343.056464 -269.059152)
		(mid 342.77729 -269.134917)
		(end 342.497156 -269.062708)
		(width 0.088646)
		(layer "In11.Cu")
		(net "M_D_CPU0_SA_DQ<25>")
	)
	(arc
		(start 337.79206 -269.059152)
		(mid 337.604862 -269.009009)
		(end 337.417664 -269.059152)
		(width 0.088646)
		(layer "In11.Cu")
		(net "M_D_CPU0_SA_DQ<25>")
	)
	(arc
		(start 335.91246 -269.059152)
		(mid 335.725262 -269.009009)
		(end 335.538064 -269.059152)
		(width 0.088646)
		(layer "In11.Cu")
		(net "M_D_CPU0_SA_DQ<25>")
	)
	(segment
		(start 257.414776 -288.266632)
		(end 256.080514 -288.266632)
		(width 0.20066)
		(layer "F.Cu")
		(net "M_D_CPU0_SA_DQ<24>")
	)
	(segment
		(start 258.49453 -287.833562)
		(end 258.28498 -288.043112)
		(width 0.20066)
		(layer "F.Cu")
		(net "M_D_CPU0_SA_DQ<24>")
	)
	(segment
		(start 259.064506 -287.84169)
		(end 259.056378 -287.833562)
		(width 0.101854)
		(layer "F.Cu")
		(net "M_D_CPU0_SA_DQ<24>")
	)
	(segment
		(start 261.381494 -287.84169)
		(end 259.31241 -287.84169)
		(width 0.1016)
		(layer "F.Cu")
		(net "M_D_CPU0_SA_DQ<24>")
	)
	(segment
		(start 258.28498 -288.043112)
		(end 258.28498 -288.332672)
		(width 0.20066)
		(layer "F.Cu")
		(net "M_D_CPU0_SA_DQ<24>")
	)
	(segment
		(start 263.624314 -288.266632)
		(end 262.255254 -288.266632)
		(width 0.20066)
		(layer "F.Cu")
		(net "M_D_CPU0_SA_DQ<24>")
	)
	(segment
		(start 259.31241 -287.84169)
		(end 259.064506 -287.84169)
		(width 0.101854)
		(layer "F.Cu")
		(net "M_D_CPU0_SA_DQ<24>")
	)
	(segment
		(start 261.830312 -287.84169)
		(end 261.381494 -287.84169)
		(width 0.20066)
		(layer "F.Cu")
		(net "M_D_CPU0_SA_DQ<24>")
	)
	(segment
		(start 259.056378 -287.833562)
		(end 258.49453 -287.833562)
		(width 0.20066)
		(layer "F.Cu")
		(net "M_D_CPU0_SA_DQ<24>")
	)
	(segment
		(start 264.729214 -288.266632)
		(end 263.624314 -288.266632)
		(width 0.20066)
		(layer "F.Cu")
		(net "M_D_CPU0_SA_DQ<24>")
	)
	(segment
		(start 347.003116 -268.84757)
		(end 347.002862 -268.847824)
		(width 0.20066)
		(layer "F.Cu")
		(net "M_D_CPU0_SA_DQ<24>")
	)
	(segment
		(start 347.002862 -268.847824)
		(end 347.002862 -269.38351)
		(width 0.20066)
		(layer "F.Cu")
		(net "M_D_CPU0_SA_DQ<24>")
	)
	(segment
		(start 262.255254 -288.266632)
		(end 261.830312 -287.84169)
		(width 0.20066)
		(layer "F.Cu")
		(net "M_D_CPU0_SA_DQ<24>")
	)
	(segment
		(start 258.11226 -288.505392)
		(end 257.653536 -288.505392)
		(width 0.20066)
		(layer "F.Cu")
		(net "M_D_CPU0_SA_DQ<24>")
	)
	(segment
		(start 258.28498 -288.332672)
		(end 258.11226 -288.505392)
		(width 0.20066)
		(layer "F.Cu")
		(net "M_D_CPU0_SA_DQ<24>")
	)
	(segment
		(start 257.653536 -288.505392)
		(end 257.414776 -288.266632)
		(width 0.20066)
		(layer "F.Cu")
		(net "M_D_CPU0_SA_DQ<24>")
	)
	(segment
		(start 296.839894 -289.336226)
		(end 295.442894 -289.542474)
		(width 0.18288)
		(layer "In11.Cu")
		(net "M_D_CPU0_SA_DQ<24>")
	)
	(segment
		(start 314.951872 -283.96819)
		(end 311.960514 -283.96819)
		(width 0.18288)
		(layer "In11.Cu")
		(net "M_D_CPU0_SA_DQ<24>")
	)
	(segment
		(start 333.305404 -269.948914)
		(end 332.895448 -270.35887)
		(width 0.088646)
		(layer "In11.Cu")
		(net "M_D_CPU0_SA_DQ<24>")
	)
	(segment
		(start 302.808894 -288.015426)
		(end 302.204628 -288.243264)
		(width 0.18288)
		(layer "In11.Cu")
		(net "M_D_CPU0_SA_DQ<24>")
	)
	(segment
		(start 267.692886 -288.064956)
		(end 267.692886 -289.406838)
		(width 0.18288)
		(layer "In11.Cu")
		(net "M_D_CPU0_SA_DQ<24>")
	)
	(segment
		(start 284.751526 -288.538158)
		(end 284.597094 -288.69259)
		(width 0.18288)
		(layer "In11.Cu")
		(net "M_D_CPU0_SA_DQ<24>")
	)
	(segment
		(start 297.220894 -289.336226)
		(end 296.839894 -289.336226)
		(width 0.18288)
		(layer "In11.Cu")
		(net "M_D_CPU0_SA_DQ<24>")
	)
	(segment
		(start 293.776908 -289.542474)
		(end 293.026592 -289.641026)
		(width 0.18288)
		(layer "In11.Cu")
		(net "M_D_CPU0_SA_DQ<24>")
	)
	(segment
		(start 265.589766 -288.88436)
		(end 265.396726 -288.69132)
		(width 0.18288)
		(layer "In11.Cu")
		(net "M_D_CPU0_SA_DQ<24>")
	)
	(segment
		(start 266.991846 -288.91611)
		(end 266.798806 -288.72307)
		(width 0.18288)
		(layer "In11.Cu")
		(net "M_D_CPU0_SA_DQ<24>")
	)
	(segment
		(start 265.589766 -289.406838)
		(end 265.589766 -288.88436)
		(width 0.18288)
		(layer "In11.Cu")
		(net "M_D_CPU0_SA_DQ<24>")
	)
	(segment
		(start 340.151974 -269.879318)
		(end 340.14156 -269.873222)
		(width 0.088646)
		(layer "In11.Cu")
		(net "M_D_CPU0_SA_DQ<24>")
	)
	(segment
		(start 311.063132 -284.865572)
		(end 310.055514 -285.282894)
		(width 0.18288)
		(layer "In11.Cu")
		(net "M_D_CPU0_SA_DQ<24>")
	)
	(segment
		(start 266.290806 -289.406838)
		(end 266.097766 -289.599878)
		(width 0.18288)
		(layer "In11.Cu")
		(net "M_D_CPU0_SA_DQ<24>")
	)
	(segment
		(start 338.272374 -269.879318)
		(end 338.26196 -269.873222)
		(width 0.088646)
		(layer "In11.Cu")
		(net "M_D_CPU0_SA_DQ<24>")
	)
	(segment
		(start 331.261212 -271.945354)
		(end 331.004672 -271.945354)
		(width 0.088646)
		(layer "In11.Cu")
		(net "M_D_CPU0_SA_DQ<24>")
	)
	(segment
		(start 282.555696 -289.227768)
		(end 282.133294 -289.412426)
		(width 0.18288)
		(layer "In11.Cu")
		(net "M_D_CPU0_SA_DQ<24>")
	)
	(segment
		(start 282.133294 -289.412426)
		(end 281.218894 -289.412426)
		(width 0.18288)
		(layer "In11.Cu")
		(net "M_D_CPU0_SA_DQ<24>")
	)
	(segment
		(start 326.974708 -271.945354)
		(end 314.951872 -283.96819)
		(width 0.18288)
		(layer "In11.Cu")
		(net "M_D_CPU0_SA_DQ<24>")
	)
	(segment
		(start 283.090874 -288.69259)
		(end 282.555696 -289.227768)
		(width 0.18288)
		(layer "In11.Cu")
		(net "M_D_CPU0_SA_DQ<24>")
	)
	(segment
		(start 299.506894 -288.69259)
		(end 298.36364 -288.69259)
		(width 0.18288)
		(layer "In11.Cu")
		(net "M_D_CPU0_SA_DQ<24>")
	)
	(segment
		(start 265.396726 -288.69132)
		(end 265.153902 -288.69132)
		(width 0.18288)
		(layer "In11.Cu")
		(net "M_D_CPU0_SA_DQ<24>")
	)
	(segment
		(start 291.505894 -289.361626)
		(end 290.975034 -289.361626)
		(width 0.18288)
		(layer "In11.Cu")
		(net "M_D_CPU0_SA_DQ<24>")
	)
	(segment
		(start 302.204628 -288.243264)
		(end 302.189642 -288.246058)
		(width 0.18288)
		(layer "In11.Cu")
		(net "M_D_CPU0_SA_DQ<24>")
	)
	(segment
		(start 273.51101 -288.50082)
		(end 269.759684 -288.50082)
		(width 0.18288)
		(layer "In11.Cu")
		(net "M_D_CPU0_SA_DQ<24>")
	)
	(segment
		(start 311.960514 -283.96819)
		(end 311.063132 -284.865572)
		(width 0.18288)
		(layer "In11.Cu")
		(net "M_D_CPU0_SA_DQ<24>")
	)
	(segment
		(start 342.975946 -269.881858)
		(end 342.961214 -269.873222)
		(width 0.088646)
		(layer "In11.Cu")
		(net "M_D_CPU0_SA_DQ<24>")
	)
	(segment
		(start 278.064214 -289.542474)
		(end 277.940262 -289.666426)
		(width 0.18288)
		(layer "In11.Cu")
		(net "M_D_CPU0_SA_DQ<24>")
	)
	(segment
		(start 306.76723 -285.958026)
		(end 306.432204 -285.958026)
		(width 0.18288)
		(layer "In11.Cu")
		(net "M_D_CPU0_SA_DQ<24>")
	)
	(segment
		(start 288.614866 -288.538158)
		(end 284.751526 -288.538158)
		(width 0.18288)
		(layer "In11.Cu")
		(net "M_D_CPU0_SA_DQ<24>")
	)
	(segment
		(start 342.036146 -269.881858)
		(end 342.021414 -269.873222)
		(width 0.088646)
		(layer "In11.Cu")
		(net "M_D_CPU0_SA_DQ<24>")
	)
	(segment
		(start 298.36364 -288.69259)
		(end 297.220894 -289.336226)
		(width 0.18288)
		(layer "In11.Cu")
		(net "M_D_CPU0_SA_DQ<24>")
	)
	(segment
		(start 266.097766 -289.599878)
		(end 265.782806 -289.599878)
		(width 0.18288)
		(layer "In11.Cu")
		(net "M_D_CPU0_SA_DQ<24>")
	)
	(segment
		(start 333.845662 -269.948914)
		(end 333.305404 -269.948914)
		(width 0.088646)
		(layer "In11.Cu")
		(net "M_D_CPU0_SA_DQ<24>")
	)
	(segment
		(start 331.454252 -271.469612)
		(end 331.454252 -271.752314)
		(width 0.088646)
		(layer "In11.Cu")
		(net "M_D_CPU0_SA_DQ<24>")
	)
	(segment
		(start 269.10157 -287.842706)
		(end 267.915136 -287.842706)
		(width 0.18288)
		(layer "In11.Cu")
		(net "M_D_CPU0_SA_DQ<24>")
	)
	(segment
		(start 284.597094 -288.69259)
		(end 283.090874 -288.69259)
		(width 0.18288)
		(layer "In11.Cu")
		(net "M_D_CPU0_SA_DQ<24>")
	)
	(segment
		(start 275.51507 -288.980118)
		(end 273.990308 -288.980118)
		(width 0.18288)
		(layer "In11.Cu")
		(net "M_D_CPU0_SA_DQ<24>")
	)
	(segment
		(start 307.796692 -286.157924)
		(end 306.967128 -286.157924)
		(width 0.18288)
		(layer "In11.Cu")
		(net "M_D_CPU0_SA_DQ<24>")
	)
	(segment
		(start 266.483846 -288.72307)
		(end 266.290806 -288.91611)
		(width 0.18288)
		(layer "In11.Cu")
		(net "M_D_CPU0_SA_DQ<24>")
	)
	(segment
		(start 344.855546 -269.881858)
		(end 344.840814 -269.873222)
		(width 0.088646)
		(layer "In11.Cu")
		(net "M_D_CPU0_SA_DQ<24>")
	)
	(segment
		(start 266.290806 -288.91611)
		(end 266.290806 -289.406838)
		(width 0.18288)
		(layer "In11.Cu")
		(net "M_D_CPU0_SA_DQ<24>")
	)
	(segment
		(start 267.692886 -289.406838)
		(end 267.499846 -289.599878)
		(width 0.18288)
		(layer "In11.Cu")
		(net "M_D_CPU0_SA_DQ<24>")
	)
	(segment
		(start 289.135058 -289.05835)
		(end 288.614866 -288.538158)
		(width 0.18288)
		(layer "In11.Cu")
		(net "M_D_CPU0_SA_DQ<24>")
	)
	(segment
		(start 300.345094 -288.599626)
		(end 299.506894 -288.69259)
		(width 0.18288)
		(layer "In11.Cu")
		(net "M_D_CPU0_SA_DQ<24>")
	)
	(segment
		(start 308.671722 -285.282894)
		(end 307.796692 -286.157924)
		(width 0.18288)
		(layer "In11.Cu")
		(net "M_D_CPU0_SA_DQ<24>")
	)
	(segment
		(start 310.055514 -285.282894)
		(end 308.671722 -285.282894)
		(width 0.18288)
		(layer "In11.Cu")
		(net "M_D_CPU0_SA_DQ<24>")
	)
	(segment
		(start 341.096346 -269.881858)
		(end 341.081614 -269.873222)
		(width 0.088646)
		(layer "In11.Cu")
		(net "M_D_CPU0_SA_DQ<24>")
	)
	(segment
		(start 266.798806 -288.72307)
		(end 266.483846 -288.72307)
		(width 0.18288)
		(layer "In11.Cu")
		(net "M_D_CPU0_SA_DQ<24>")
	)
	(segment
		(start 295.442894 -289.542474)
		(end 293.776908 -289.542474)
		(width 0.18288)
		(layer "In11.Cu")
		(net "M_D_CPU0_SA_DQ<24>")
	)
	(segment
		(start 339.767164 -269.873222)
		(end 339.75675 -269.879318)
		(width 0.088646)
		(layer "In11.Cu")
		(net "M_D_CPU0_SA_DQ<24>")
	)
	(segment
		(start 276.342094 -289.336226)
		(end 275.871178 -289.336226)
		(width 0.18288)
		(layer "In11.Cu")
		(net "M_D_CPU0_SA_DQ<24>")
	)
	(segment
		(start 306.967128 -286.157924)
		(end 306.76723 -285.958026)
		(width 0.18288)
		(layer "In11.Cu")
		(net "M_D_CPU0_SA_DQ<24>")
	)
	(segment
		(start 265.782806 -289.599878)
		(end 265.589766 -289.406838)
		(width 0.18288)
		(layer "In11.Cu")
		(net "M_D_CPU0_SA_DQ<24>")
	)
	(segment
		(start 265.153902 -288.69132)
		(end 264.729214 -288.266632)
		(width 0.18288)
		(layer "In11.Cu")
		(net "M_D_CPU0_SA_DQ<24>")
	)
	(segment
		(start 331.454252 -271.752314)
		(end 331.261212 -271.945354)
		(width 0.088646)
		(layer "In11.Cu")
		(net "M_D_CPU0_SA_DQ<24>")
	)
	(segment
		(start 304.264568 -287.316672)
		(end 302.808894 -288.015426)
		(width 0.18288)
		(layer "In11.Cu")
		(net "M_D_CPU0_SA_DQ<24>")
	)
	(segment
		(start 293.026592 -289.641026)
		(end 292.399974 -289.641026)
		(width 0.18288)
		(layer "In11.Cu")
		(net "M_D_CPU0_SA_DQ<24>")
	)
	(segment
		(start 275.871178 -289.336226)
		(end 275.51507 -288.980118)
		(width 0.18288)
		(layer "In11.Cu")
		(net "M_D_CPU0_SA_DQ<24>")
	)
	(segment
		(start 332.895448 -270.35887)
		(end 332.564994 -270.35887)
		(width 0.088646)
		(layer "In11.Cu")
		(net "M_D_CPU0_SA_DQ<24>")
	)
	(segment
		(start 292.399974 -289.641026)
		(end 291.505894 -289.361626)
		(width 0.18288)
		(layer "In11.Cu")
		(net "M_D_CPU0_SA_DQ<24>")
	)
	(segment
		(start 302.189642 -288.246058)
		(end 300.345094 -288.599626)
		(width 0.18288)
		(layer "In11.Cu")
		(net "M_D_CPU0_SA_DQ<24>")
	)
	(segment
		(start 331.004672 -271.945354)
		(end 326.974708 -271.945354)
		(width 0.18288)
		(layer "In11.Cu")
		(net "M_D_CPU0_SA_DQ<24>")
	)
	(segment
		(start 267.915136 -287.842706)
		(end 267.692886 -288.064956)
		(width 0.18288)
		(layer "In11.Cu")
		(net "M_D_CPU0_SA_DQ<24>")
	)
	(segment
		(start 290.975034 -289.361626)
		(end 289.135058 -289.05835)
		(width 0.18288)
		(layer "In11.Cu")
		(net "M_D_CPU0_SA_DQ<24>")
	)
	(segment
		(start 306.432204 -285.958026)
		(end 305.364896 -286.39643)
		(width 0.18288)
		(layer "In11.Cu")
		(net "M_D_CPU0_SA_DQ<24>")
	)
	(segment
		(start 346.440252 -269.81785)
		(end 346.33535 -269.879318)
		(width 0.088646)
		(layer "In11.Cu")
		(net "M_D_CPU0_SA_DQ<24>")
	)
	(segment
		(start 332.564994 -270.35887)
		(end 331.454252 -271.469612)
		(width 0.088646)
		(layer "In11.Cu")
		(net "M_D_CPU0_SA_DQ<24>")
	)
	(segment
		(start 267.184886 -289.599878)
		(end 266.991846 -289.406838)
		(width 0.18288)
		(layer "In11.Cu")
		(net "M_D_CPU0_SA_DQ<24>")
	)
	(segment
		(start 273.990308 -288.980118)
		(end 273.51101 -288.50082)
		(width 0.18288)
		(layer "In11.Cu")
		(net "M_D_CPU0_SA_DQ<24>")
	)
	(segment
		(start 281.218894 -289.412426)
		(end 280.304494 -289.542474)
		(width 0.18288)
		(layer "In11.Cu")
		(net "M_D_CPU0_SA_DQ<24>")
	)
	(segment
		(start 343.915746 -269.881858)
		(end 343.901014 -269.873222)
		(width 0.088646)
		(layer "In11.Cu")
		(net "M_D_CPU0_SA_DQ<24>")
	)
	(segment
		(start 280.304494 -289.542474)
		(end 278.064214 -289.542474)
		(width 0.18288)
		(layer "In11.Cu")
		(net "M_D_CPU0_SA_DQ<24>")
	)
	(segment
		(start 277.940262 -289.666426)
		(end 277.535894 -289.666426)
		(width 0.18288)
		(layer "In11.Cu")
		(net "M_D_CPU0_SA_DQ<24>")
	)
	(segment
		(start 267.499846 -289.599878)
		(end 267.184886 -289.599878)
		(width 0.18288)
		(layer "In11.Cu")
		(net "M_D_CPU0_SA_DQ<24>")
	)
	(segment
		(start 277.535894 -289.666426)
		(end 276.342094 -289.336226)
		(width 0.18288)
		(layer "In11.Cu")
		(net "M_D_CPU0_SA_DQ<24>")
	)
	(segment
		(start 266.991846 -289.406838)
		(end 266.991846 -288.91611)
		(width 0.18288)
		(layer "In11.Cu")
		(net "M_D_CPU0_SA_DQ<24>")
	)
	(segment
		(start 305.364896 -286.39643)
		(end 304.264568 -287.316672)
		(width 0.18288)
		(layer "In11.Cu")
		(net "M_D_CPU0_SA_DQ<24>")
	)
	(segment
		(start 269.759684 -288.50082)
		(end 269.10157 -287.842706)
		(width 0.18288)
		(layer "In11.Cu")
		(net "M_D_CPU0_SA_DQ<24>")
	)
	(arc
		(start 342.021414 -269.873222)
		(mid 341.834216 -269.823079)
		(end 341.647018 -269.873222)
		(width 0.088646)
		(layer "In11.Cu")
		(net "M_D_CPU0_SA_DQ<24>")
	)
	(arc
		(start 335.068164 -269.873222)
		(mid 334.785462 -269.948964)
		(end 334.50276 -269.873222)
		(width 0.088646)
		(layer "In11.Cu")
		(net "M_D_CPU0_SA_DQ<24>")
	)
	(arc
		(start 336.38236 -269.873222)
		(mid 336.195162 -269.823079)
		(end 336.007964 -269.873222)
		(width 0.088646)
		(layer "In11.Cu")
		(net "M_D_CPU0_SA_DQ<24>")
	)
	(arc
		(start 343.526618 -269.873222)
		(mid 343.252389 -269.949147)
		(end 342.975946 -269.881858)
		(width 0.088646)
		(layer "In11.Cu")
		(net "M_D_CPU0_SA_DQ<24>")
	)
	(arc
		(start 344.466418 -269.873222)
		(mid 344.192189 -269.949147)
		(end 343.915746 -269.881858)
		(width 0.088646)
		(layer "In11.Cu")
		(net "M_D_CPU0_SA_DQ<24>")
	)
	(arc
		(start 335.44256 -269.873222)
		(mid 335.255362 -269.823079)
		(end 335.068164 -269.873222)
		(width 0.088646)
		(layer "In11.Cu")
		(net "M_D_CPU0_SA_DQ<24>")
	)
	(arc
		(start 347.002862 -269.38351)
		(mid 346.735465 -269.618695)
		(end 346.440252 -269.81785)
		(width 0.088646)
		(layer "In11.Cu")
		(net "M_D_CPU0_SA_DQ<24>")
	)
	(arc
		(start 345.406218 -269.873222)
		(mid 345.131989 -269.949147)
		(end 344.855546 -269.881858)
		(width 0.088646)
		(layer "In11.Cu")
		(net "M_D_CPU0_SA_DQ<24>")
	)
	(arc
		(start 337.887564 -269.873222)
		(mid 337.604862 -269.948964)
		(end 337.32216 -269.873222)
		(width 0.088646)
		(layer "In11.Cu")
		(net "M_D_CPU0_SA_DQ<24>")
	)
	(arc
		(start 334.50276 -269.873222)
		(mid 334.315562 -269.823079)
		(end 334.128364 -269.873222)
		(width 0.088646)
		(layer "In11.Cu")
		(net "M_D_CPU0_SA_DQ<24>")
	)
	(arc
		(start 341.081614 -269.873222)
		(mid 340.894416 -269.823079)
		(end 340.707218 -269.873222)
		(width 0.088646)
		(layer "In11.Cu")
		(net "M_D_CPU0_SA_DQ<24>")
	)
	(arc
		(start 338.827618 -269.873222)
		(mid 338.550805 -269.949058)
		(end 338.272374 -269.879318)
		(width 0.088646)
		(layer "In11.Cu")
		(net "M_D_CPU0_SA_DQ<24>")
	)
	(arc
		(start 338.26196 -269.873222)
		(mid 338.074762 -269.823079)
		(end 337.887564 -269.873222)
		(width 0.088646)
		(layer "In11.Cu")
		(net "M_D_CPU0_SA_DQ<24>")
	)
	(arc
		(start 340.14156 -269.873222)
		(mid 339.954362 -269.823079)
		(end 339.767164 -269.873222)
		(width 0.088646)
		(layer "In11.Cu")
		(net "M_D_CPU0_SA_DQ<24>")
	)
	(arc
		(start 336.007964 -269.873222)
		(mid 335.725262 -269.948964)
		(end 335.44256 -269.873222)
		(width 0.088646)
		(layer "In11.Cu")
		(net "M_D_CPU0_SA_DQ<24>")
	)
	(arc
		(start 341.647018 -269.873222)
		(mid 341.372789 -269.949147)
		(end 341.096346 -269.881858)
		(width 0.088646)
		(layer "In11.Cu")
		(net "M_D_CPU0_SA_DQ<24>")
	)
	(arc
		(start 337.32216 -269.873222)
		(mid 337.134962 -269.823079)
		(end 336.947764 -269.873222)
		(width 0.088646)
		(layer "In11.Cu")
		(net "M_D_CPU0_SA_DQ<24>")
	)
	(arc
		(start 339.75675 -269.879318)
		(mid 339.478572 -269.94901)
		(end 339.202014 -269.873222)
		(width 0.088646)
		(layer "In11.Cu")
		(net "M_D_CPU0_SA_DQ<24>")
	)
	(arc
		(start 339.202014 -269.873222)
		(mid 339.014816 -269.823079)
		(end 338.827618 -269.873222)
		(width 0.088646)
		(layer "In11.Cu")
		(net "M_D_CPU0_SA_DQ<24>")
	)
	(arc
		(start 340.707218 -269.873222)
		(mid 340.430405 -269.949058)
		(end 340.151974 -269.879318)
		(width 0.088646)
		(layer "In11.Cu")
		(net "M_D_CPU0_SA_DQ<24>")
	)
	(arc
		(start 334.128364 -269.873222)
		(mid 333.991998 -269.9297)
		(end 333.845662 -269.948914)
		(width 0.088646)
		(layer "In11.Cu")
		(net "M_D_CPU0_SA_DQ<24>")
	)
	(arc
		(start 346.33535 -269.879318)
		(mid 346.057172 -269.94901)
		(end 345.780614 -269.873222)
		(width 0.088646)
		(layer "In11.Cu")
		(net "M_D_CPU0_SA_DQ<24>")
	)
	(arc
		(start 344.840814 -269.873222)
		(mid 344.653616 -269.823079)
		(end 344.466418 -269.873222)
		(width 0.088646)
		(layer "In11.Cu")
		(net "M_D_CPU0_SA_DQ<24>")
	)
	(arc
		(start 336.947764 -269.873222)
		(mid 336.665062 -269.948964)
		(end 336.38236 -269.873222)
		(width 0.088646)
		(layer "In11.Cu")
		(net "M_D_CPU0_SA_DQ<24>")
	)
	(arc
		(start 342.961214 -269.873222)
		(mid 342.774016 -269.823079)
		(end 342.586818 -269.873222)
		(width 0.088646)
		(layer "In11.Cu")
		(net "M_D_CPU0_SA_DQ<24>")
	)
	(arc
		(start 343.901014 -269.873222)
		(mid 343.713816 -269.823079)
		(end 343.526618 -269.873222)
		(width 0.088646)
		(layer "In11.Cu")
		(net "M_D_CPU0_SA_DQ<24>")
	)
	(arc
		(start 342.586818 -269.873222)
		(mid 342.312589 -269.949147)
		(end 342.036146 -269.881858)
		(width 0.088646)
		(layer "In11.Cu")
		(net "M_D_CPU0_SA_DQ<24>")
	)
	(arc
		(start 345.780614 -269.873222)
		(mid 345.593416 -269.823079)
		(end 345.406218 -269.873222)
		(width 0.088646)
		(layer "In11.Cu")
		(net "M_D_CPU0_SA_DQ<24>")
	)
	(segment
		(start 265.518646 -289.392614)
		(end 265.369548 -289.541712)
		(width 0.20066)
		(layer "F.Cu")
		(net "M_D_CPU0_SA_DQ<23>")
	)
	(segment
		(start 266.700762 -289.324288)
		(end 266.25423 -289.324288)
		(width 0.20066)
		(layer "F.Cu")
		(net "M_D_CPU0_SA_DQ<23>")
	)
	(segment
		(start 268.829282 -289.11677)
		(end 267.724382 -289.11677)
		(width 0.20066)
		(layer "F.Cu")
		(net "M_D_CPU0_SA_DQ<23>")
	)
	(segment
		(start 266.90828 -289.11677)
		(end 266.700762 -289.324288)
		(width 0.20066)
		(layer "F.Cu")
		(net "M_D_CPU0_SA_DQ<23>")
	)
	(segment
		(start 266.25423 -289.324288)
		(end 266.042394 -289.112452)
		(width 0.20066)
		(layer "F.Cu")
		(net "M_D_CPU0_SA_DQ<23>")
	)
	(segment
		(start 262.752332 -289.541712)
		(end 262.514334 -289.541712)
		(width 0.101854)
		(layer "F.Cu")
		(net "M_D_CPU0_SA_DQ<23>")
	)
	(segment
		(start 262.146288 -289.555936)
		(end 262.003794 -289.413442)
		(width 0.20066)
		(layer "F.Cu")
		(net "M_D_CPU0_SA_DQ<23>")
	)
	(segment
		(start 265.64717 -289.112452)
		(end 265.518646 -289.240976)
		(width 0.20066)
		(layer "F.Cu")
		(net "M_D_CPU0_SA_DQ<23>")
	)
	(segment
		(start 262.003794 -289.413442)
		(end 262.003794 -289.242754)
		(width 0.20066)
		(layer "F.Cu")
		(net "M_D_CPU0_SA_DQ<23>")
	)
	(segment
		(start 264.825226 -289.541712)
		(end 262.752332 -289.541712)
		(width 0.1016)
		(layer "F.Cu")
		(net "M_D_CPU0_SA_DQ<23>")
	)
	(segment
		(start 262.514334 -289.541712)
		(end 262.50011 -289.555936)
		(width 0.101854)
		(layer "F.Cu")
		(net "M_D_CPU0_SA_DQ<23>")
	)
	(segment
		(start 265.369548 -289.541712)
		(end 264.825226 -289.541712)
		(width 0.20066)
		(layer "F.Cu")
		(net "M_D_CPU0_SA_DQ<23>")
	)
	(segment
		(start 262.003794 -289.242754)
		(end 261.87781 -289.11677)
		(width 0.20066)
		(layer "F.Cu")
		(net "M_D_CPU0_SA_DQ<23>")
	)
	(segment
		(start 262.50011 -289.555936)
		(end 262.146288 -289.555936)
		(width 0.20066)
		(layer "F.Cu")
		(net "M_D_CPU0_SA_DQ<23>")
	)
	(segment
		(start 267.724382 -289.11677)
		(end 266.90828 -289.11677)
		(width 0.20066)
		(layer "F.Cu")
		(net "M_D_CPU0_SA_DQ<23>")
	)
	(segment
		(start 261.87781 -289.11677)
		(end 260.180582 -289.11677)
		(width 0.20066)
		(layer "F.Cu")
		(net "M_D_CPU0_SA_DQ<23>")
	)
	(segment
		(start 265.518646 -289.240976)
		(end 265.518646 -289.392614)
		(width 0.20066)
		(layer "F.Cu")
		(net "M_D_CPU0_SA_DQ<23>")
	)
	(segment
		(start 266.042394 -289.112452)
		(end 265.64717 -289.112452)
		(width 0.20066)
		(layer "F.Cu")
		(net "M_D_CPU0_SA_DQ<23>")
	)
	(arc
		(start 347.942916 -270.475456)
		(mid 347.942852 -270.743426)
		(end 347.942662 -271.011396)
		(width 0.20066)
		(layer "F.Cu")
		(net "M_D_CPU0_SA_DQ<23>")
	)
	(segment
		(start 296.645584 -290.392104)
		(end 294.21582 -290.392104)
		(width 0.18288)
		(layer "In11.Cu")
		(net "M_D_CPU0_SA_DQ<23>")
	)
	(segment
		(start 300.948598 -289.824414)
		(end 299.907452 -289.824414)
		(width 0.18288)
		(layer "In11.Cu")
		(net "M_D_CPU0_SA_DQ<23>")
	)
	(segment
		(start 314.644024 -285.431992)
		(end 313.823096 -285.431992)
		(width 0.18288)
		(layer "In11.Cu")
		(net "M_D_CPU0_SA_DQ<23>")
	)
	(segment
		(start 307.084984 -286.960818)
		(end 306.868576 -287.177226)
		(width 0.18288)
		(layer "In11.Cu")
		(net "M_D_CPU0_SA_DQ<23>")
	)
	(segment
		(start 312.735976 -285.431992)
		(end 312.04027 -285.431992)
		(width 0.18288)
		(layer "In11.Cu")
		(net "M_D_CPU0_SA_DQ<23>")
	)
	(segment
		(start 274.032218 -290.555426)
		(end 273.182588 -289.705796)
		(width 0.18288)
		(layer "In11.Cu")
		(net "M_D_CPU0_SA_DQ<23>")
	)
	(segment
		(start 308.69255 -286.453834)
		(end 308.185566 -286.960818)
		(width 0.18288)
		(layer "In11.Cu")
		(net "M_D_CPU0_SA_DQ<23>")
	)
	(segment
		(start 306.868576 -287.177226)
		(end 306.110894 -287.177226)
		(width 0.18288)
		(layer "In11.Cu")
		(net "M_D_CPU0_SA_DQ<23>")
	)
	(segment
		(start 301.141638 -289.438842)
		(end 301.141638 -289.631374)
		(width 0.18288)
		(layer "In11.Cu")
		(net "M_D_CPU0_SA_DQ<23>")
	)
	(segment
		(start 293.778178 -290.57346)
		(end 292.958012 -291.393626)
		(width 0.18288)
		(layer "In11.Cu")
		(net "M_D_CPU0_SA_DQ<23>")
	)
	(segment
		(start 347.942662 -271.011396)
		(end 347.629988 -271.011396)
		(width 0.088646)
		(layer "In11.Cu")
		(net "M_D_CPU0_SA_DQ<23>")
	)
	(segment
		(start 278.86025 -290.370768)
		(end 278.578818 -290.370768)
		(width 0.18288)
		(layer "In11.Cu")
		(net "M_D_CPU0_SA_DQ<23>")
	)
	(segment
		(start 312.04027 -285.431992)
		(end 309.57393 -286.453834)
		(width 0.18288)
		(layer "In11.Cu")
		(net "M_D_CPU0_SA_DQ<23>")
	)
	(segment
		(start 301.357538 -289.222942)
		(end 301.141638 -289.438842)
		(width 0.18288)
		(layer "In11.Cu")
		(net "M_D_CPU0_SA_DQ<23>")
	)
	(segment
		(start 290.421822 -291.233098)
		(end 290.228782 -291.040058)
		(width 0.18288)
		(layer "In11.Cu")
		(net "M_D_CPU0_SA_DQ<23>")
	)
	(segment
		(start 338.272374 -270.515842)
		(end 338.26196 -270.521938)
		(width 0.088646)
		(layer "In11.Cu")
		(net "M_D_CPU0_SA_DQ<23>")
	)
	(segment
		(start 275.365972 -290.032948)
		(end 275.172932 -289.839908)
		(width 0.18288)
		(layer "In11.Cu")
		(net "M_D_CPU0_SA_DQ<23>")
	)
	(segment
		(start 331.246988 -272.747994)
		(end 331.004672 -272.747994)
		(width 0.088646)
		(layer "In11.Cu")
		(net "M_D_CPU0_SA_DQ<23>")
	)
	(segment
		(start 340.151974 -270.515842)
		(end 340.14156 -270.521938)
		(width 0.088646)
		(layer "In11.Cu")
		(net "M_D_CPU0_SA_DQ<23>")
	)
	(segment
		(start 280.371042 -290.52901)
		(end 280.234136 -290.392104)
		(width 0.18288)
		(layer "In11.Cu")
		(net "M_D_CPU0_SA_DQ<23>")
	)
	(segment
		(start 301.141638 -289.631374)
		(end 300.948598 -289.824414)
		(width 0.18288)
		(layer "In11.Cu")
		(net "M_D_CPU0_SA_DQ<23>")
	)
	(segment
		(start 287.777174 -289.660838)
		(end 284.501082 -289.660838)
		(width 0.18288)
		(layer "In11.Cu")
		(net "M_D_CPU0_SA_DQ<23>")
	)
	(segment
		(start 275.365972 -290.362386)
		(end 275.365972 -290.032948)
		(width 0.18288)
		(layer "In11.Cu")
		(net "M_D_CPU0_SA_DQ<23>")
	)
	(segment
		(start 292.958012 -291.393626)
		(end 292.344094 -291.393626)
		(width 0.18288)
		(layer "In11.Cu")
		(net "M_D_CPU0_SA_DQ<23>")
	)
	(segment
		(start 271.063212 -289.349434)
		(end 270.70685 -289.705796)
		(width 0.18288)
		(layer "In11.Cu")
		(net "M_D_CPU0_SA_DQ<23>")
	)
	(segment
		(start 296.74439 -290.49091)
		(end 296.645584 -290.392104)
		(width 0.18288)
		(layer "In11.Cu")
		(net "M_D_CPU0_SA_DQ<23>")
	)
	(segment
		(start 313.630056 -285.238952)
		(end 313.630056 -284.989778)
		(width 0.18288)
		(layer "In11.Cu")
		(net "M_D_CPU0_SA_DQ<23>")
	)
	(segment
		(start 277.560278 -291.48151)
		(end 276.634194 -290.555426)
		(width 0.18288)
		(layer "In11.Cu")
		(net "M_D_CPU0_SA_DQ<23>")
	)
	(segment
		(start 302.035718 -289.824414)
		(end 301.842678 -289.631374)
		(width 0.18288)
		(layer "In11.Cu")
		(net "M_D_CPU0_SA_DQ<23>")
	)
	(segment
		(start 305.637184 -287.650936)
		(end 305.215036 -287.650936)
		(width 0.18288)
		(layer "In11.Cu")
		(net "M_D_CPU0_SA_DQ<23>")
	)
	(segment
		(start 331.427582 -272.210276)
		(end 331.427582 -272.5674)
		(width 0.088646)
		(layer "In11.Cu")
		(net "M_D_CPU0_SA_DQ<23>")
	)
	(segment
		(start 274.664932 -290.032948)
		(end 274.664932 -290.362386)
		(width 0.18288)
		(layer "In11.Cu")
		(net "M_D_CPU0_SA_DQ<23>")
	)
	(segment
		(start 331.004672 -272.747994)
		(end 327.328022 -272.747994)
		(width 0.18288)
		(layer "In11.Cu")
		(net "M_D_CPU0_SA_DQ<23>")
	)
	(segment
		(start 313.823096 -285.431992)
		(end 313.630056 -285.238952)
		(width 0.18288)
		(layer "In11.Cu")
		(net "M_D_CPU0_SA_DQ<23>")
	)
	(segment
		(start 280.234136 -290.392104)
		(end 279.460198 -290.392104)
		(width 0.18288)
		(layer "In11.Cu")
		(net "M_D_CPU0_SA_DQ<23>")
	)
	(segment
		(start 346.351606 -270.52524)
		(end 346.339922 -270.518636)
		(width 0.088646)
		(layer "In11.Cu")
		(net "M_D_CPU0_SA_DQ<23>")
	)
	(segment
		(start 303.469294 -288.828226)
		(end 302.473106 -289.824414)
		(width 0.18288)
		(layer "In11.Cu")
		(net "M_D_CPU0_SA_DQ<23>")
	)
	(segment
		(start 347.287596 -270.523208)
		(end 347.285564 -270.521938)
		(width 0.088646)
		(layer "In11.Cu")
		(net "M_D_CPU0_SA_DQ<23>")
	)
	(segment
		(start 292.344094 -291.393626)
		(end 292.093396 -291.142928)
		(width 0.18288)
		(layer "In11.Cu")
		(net "M_D_CPU0_SA_DQ<23>")
	)
	(segment
		(start 308.185566 -286.960818)
		(end 307.084984 -286.960818)
		(width 0.18288)
		(layer "In11.Cu")
		(net "M_D_CPU0_SA_DQ<23>")
	)
	(segment
		(start 278.360124 -290.862258)
		(end 278.538686 -291.04082)
		(width 0.18288)
		(layer "In11.Cu")
		(net "M_D_CPU0_SA_DQ<23>")
	)
	(segment
		(start 284.38221 -289.541966)
		(end 283.494734 -289.541966)
		(width 0.18288)
		(layer "In11.Cu")
		(net "M_D_CPU0_SA_DQ<23>")
	)
	(segment
		(start 284.501082 -289.660838)
		(end 284.38221 -289.541966)
		(width 0.18288)
		(layer "In11.Cu")
		(net "M_D_CPU0_SA_DQ<23>")
	)
	(segment
		(start 304.951892 -288.336228)
		(end 304.459894 -288.828226)
		(width 0.18288)
		(layer "In11.Cu")
		(net "M_D_CPU0_SA_DQ<23>")
	)
	(segment
		(start 301.842678 -289.631374)
		(end 301.842678 -289.415982)
		(width 0.18288)
		(layer "In11.Cu")
		(net "M_D_CPU0_SA_DQ<23>")
	)
	(segment
		(start 347.285564 -270.521938)
		(end 347.279722 -270.518636)
		(width 0.088646)
		(layer "In11.Cu")
		(net "M_D_CPU0_SA_DQ<23>")
	)
	(segment
		(start 278.360124 -290.589462)
		(end 278.360124 -290.862258)
		(width 0.18288)
		(layer "In11.Cu")
		(net "M_D_CPU0_SA_DQ<23>")
	)
	(segment
		(start 291.122862 -290.516056)
		(end 290.929822 -290.709096)
		(width 0.18288)
		(layer "In11.Cu")
		(net "M_D_CPU0_SA_DQ<23>")
	)
	(segment
		(start 299.907452 -289.824414)
		(end 299.625004 -289.541966)
		(width 0.18288)
		(layer "In11.Cu")
		(net "M_D_CPU0_SA_DQ<23>")
	)
	(segment
		(start 282.50769 -290.52901)
		(end 280.371042 -290.52901)
		(width 0.18288)
		(layer "In11.Cu")
		(net "M_D_CPU0_SA_DQ<23>")
	)
	(segment
		(start 278.538686 -291.313616)
		(end 278.370792 -291.48151)
		(width 0.18288)
		(layer "In11.Cu")
		(net "M_D_CPU0_SA_DQ<23>")
	)
	(segment
		(start 305.215036 -287.650936)
		(end 304.951892 -287.91408)
		(width 0.18288)
		(layer "In11.Cu")
		(net "M_D_CPU0_SA_DQ<23>")
	)
	(segment
		(start 290.228782 -291.040058)
		(end 290.228782 -290.709096)
		(width 0.18288)
		(layer "In11.Cu")
		(net "M_D_CPU0_SA_DQ<23>")
	)
	(segment
		(start 297.40987 -290.49091)
		(end 296.74439 -290.49091)
		(width 0.18288)
		(layer "In11.Cu")
		(net "M_D_CPU0_SA_DQ<23>")
	)
	(segment
		(start 274.471892 -290.555426)
		(end 274.032218 -290.555426)
		(width 0.18288)
		(layer "In11.Cu")
		(net "M_D_CPU0_SA_DQ<23>")
	)
	(segment
		(start 275.172932 -289.839908)
		(end 274.857972 -289.839908)
		(width 0.18288)
		(layer "In11.Cu")
		(net "M_D_CPU0_SA_DQ<23>")
	)
	(segment
		(start 331.644498 -271.99336)
		(end 331.427582 -272.210276)
		(width 0.088646)
		(layer "In11.Cu")
		(net "M_D_CPU0_SA_DQ<23>")
	)
	(segment
		(start 312.929016 -284.989778)
		(end 312.929016 -285.238952)
		(width 0.18288)
		(layer "In11.Cu")
		(net "M_D_CPU0_SA_DQ<23>")
	)
	(segment
		(start 306.110894 -287.177226)
		(end 305.637184 -287.650936)
		(width 0.18288)
		(layer "In11.Cu")
		(net "M_D_CPU0_SA_DQ<23>")
	)
	(segment
		(start 290.228782 -290.709096)
		(end 290.035742 -290.516056)
		(width 0.18288)
		(layer "In11.Cu")
		(net "M_D_CPU0_SA_DQ<23>")
	)
	(segment
		(start 313.437016 -284.796738)
		(end 313.122056 -284.796738)
		(width 0.18288)
		(layer "In11.Cu")
		(net "M_D_CPU0_SA_DQ<23>")
	)
	(segment
		(start 345.411806 -270.52524)
		(end 345.400122 -270.518636)
		(width 0.088646)
		(layer "In11.Cu")
		(net "M_D_CPU0_SA_DQ<23>")
	)
	(segment
		(start 290.035742 -290.516056)
		(end 288.632392 -290.516056)
		(width 0.18288)
		(layer "In11.Cu")
		(net "M_D_CPU0_SA_DQ<23>")
	)
	(segment
		(start 278.578818 -290.370768)
		(end 278.360124 -290.589462)
		(width 0.18288)
		(layer "In11.Cu")
		(net "M_D_CPU0_SA_DQ<23>")
	)
	(segment
		(start 331.427582 -272.5674)
		(end 331.246988 -272.747994)
		(width 0.088646)
		(layer "In11.Cu")
		(net "M_D_CPU0_SA_DQ<23>")
	)
	(segment
		(start 283.494734 -289.541966)
		(end 282.50769 -290.52901)
		(width 0.18288)
		(layer "In11.Cu")
		(net "M_D_CPU0_SA_DQ<23>")
	)
	(segment
		(start 294.21582 -290.392104)
		(end 293.778178 -290.57346)
		(width 0.18288)
		(layer "In11.Cu")
		(net "M_D_CPU0_SA_DQ<23>")
	)
	(segment
		(start 275.559012 -290.555426)
		(end 275.365972 -290.362386)
		(width 0.18288)
		(layer "In11.Cu")
		(net "M_D_CPU0_SA_DQ<23>")
	)
	(segment
		(start 278.538686 -291.04082)
		(end 278.538686 -291.313616)
		(width 0.18288)
		(layer "In11.Cu")
		(net "M_D_CPU0_SA_DQ<23>")
	)
	(segment
		(start 309.57393 -286.453834)
		(end 308.69255 -286.453834)
		(width 0.18288)
		(layer "In11.Cu")
		(net "M_D_CPU0_SA_DQ<23>")
	)
	(segment
		(start 332.620874 -270.572484)
		(end 331.644498 -271.54886)
		(width 0.088646)
		(layer "In11.Cu")
		(net "M_D_CPU0_SA_DQ<23>")
	)
	(segment
		(start 327.328022 -272.747994)
		(end 314.644024 -285.431992)
		(width 0.18288)
		(layer "In11.Cu")
		(net "M_D_CPU0_SA_DQ<23>")
	)
	(segment
		(start 279.30729 -290.545012)
		(end 279.034494 -290.545012)
		(width 0.18288)
		(layer "In11.Cu")
		(net "M_D_CPU0_SA_DQ<23>")
	)
	(segment
		(start 313.630056 -284.989778)
		(end 313.437016 -284.796738)
		(width 0.18288)
		(layer "In11.Cu")
		(net "M_D_CPU0_SA_DQ<23>")
	)
	(segment
		(start 331.644498 -271.54886)
		(end 331.644498 -271.99336)
		(width 0.088646)
		(layer "In11.Cu")
		(net "M_D_CPU0_SA_DQ<23>")
	)
	(segment
		(start 341.096346 -270.513302)
		(end 341.081614 -270.521938)
		(width 0.088646)
		(layer "In11.Cu")
		(net "M_D_CPU0_SA_DQ<23>")
	)
	(segment
		(start 270.70685 -289.705796)
		(end 269.418308 -289.705796)
		(width 0.18288)
		(layer "In11.Cu")
		(net "M_D_CPU0_SA_DQ<23>")
	)
	(segment
		(start 271.40789 -289.349434)
		(end 271.063212 -289.349434)
		(width 0.18288)
		(layer "In11.Cu")
		(net "M_D_CPU0_SA_DQ<23>")
	)
	(segment
		(start 304.459894 -288.828226)
		(end 303.469294 -288.828226)
		(width 0.18288)
		(layer "In11.Cu")
		(net "M_D_CPU0_SA_DQ<23>")
	)
	(segment
		(start 302.473106 -289.824414)
		(end 302.035718 -289.824414)
		(width 0.18288)
		(layer "In11.Cu")
		(net "M_D_CPU0_SA_DQ<23>")
	)
	(segment
		(start 269.418308 -289.705796)
		(end 268.829282 -289.11677)
		(width 0.18288)
		(layer "In11.Cu")
		(net "M_D_CPU0_SA_DQ<23>")
	)
	(segment
		(start 292.093396 -291.142928)
		(end 292.093396 -290.6903)
		(width 0.18288)
		(layer "In11.Cu")
		(net "M_D_CPU0_SA_DQ<23>")
	)
	(segment
		(start 279.460198 -290.392104)
		(end 279.30729 -290.545012)
		(width 0.18288)
		(layer "In11.Cu")
		(net "M_D_CPU0_SA_DQ<23>")
	)
	(segment
		(start 301.649638 -289.222942)
		(end 301.357538 -289.222942)
		(width 0.18288)
		(layer "In11.Cu")
		(net "M_D_CPU0_SA_DQ<23>")
	)
	(segment
		(start 298.042076 -289.858704)
		(end 297.40987 -290.49091)
		(width 0.18288)
		(layer "In11.Cu")
		(net "M_D_CPU0_SA_DQ<23>")
	)
	(segment
		(start 288.632392 -290.516056)
		(end 287.777174 -289.660838)
		(width 0.18288)
		(layer "In11.Cu")
		(net "M_D_CPU0_SA_DQ<23>")
	)
	(segment
		(start 301.842678 -289.415982)
		(end 301.649638 -289.222942)
		(width 0.18288)
		(layer "In11.Cu")
		(net "M_D_CPU0_SA_DQ<23>")
	)
	(segment
		(start 274.664932 -290.362386)
		(end 274.471892 -290.555426)
		(width 0.18288)
		(layer "In11.Cu")
		(net "M_D_CPU0_SA_DQ<23>")
	)
	(segment
		(start 312.929016 -285.238952)
		(end 312.735976 -285.431992)
		(width 0.18288)
		(layer "In11.Cu")
		(net "M_D_CPU0_SA_DQ<23>")
	)
	(segment
		(start 279.034494 -290.545012)
		(end 278.86025 -290.370768)
		(width 0.18288)
		(layer "In11.Cu")
		(net "M_D_CPU0_SA_DQ<23>")
	)
	(segment
		(start 344.472006 -270.52524)
		(end 344.460322 -270.518636)
		(width 0.088646)
		(layer "In11.Cu")
		(net "M_D_CPU0_SA_DQ<23>")
	)
	(segment
		(start 290.736782 -291.233098)
		(end 290.421822 -291.233098)
		(width 0.18288)
		(layer "In11.Cu")
		(net "M_D_CPU0_SA_DQ<23>")
	)
	(segment
		(start 273.182588 -289.705796)
		(end 271.764252 -289.705796)
		(width 0.18288)
		(layer "In11.Cu")
		(net "M_D_CPU0_SA_DQ<23>")
	)
	(segment
		(start 313.122056 -284.796738)
		(end 312.929016 -284.989778)
		(width 0.18288)
		(layer "In11.Cu")
		(net "M_D_CPU0_SA_DQ<23>")
	)
	(segment
		(start 290.929822 -291.040058)
		(end 290.736782 -291.233098)
		(width 0.18288)
		(layer "In11.Cu")
		(net "M_D_CPU0_SA_DQ<23>")
	)
	(segment
		(start 299.625004 -289.541966)
		(end 298.80687 -289.541966)
		(width 0.18288)
		(layer "In11.Cu")
		(net "M_D_CPU0_SA_DQ<23>")
	)
	(segment
		(start 298.80687 -289.541966)
		(end 298.761912 -289.560508)
		(width 0.18288)
		(layer "In11.Cu")
		(net "M_D_CPU0_SA_DQ<23>")
	)
	(segment
		(start 347.629988 -271.011396)
		(end 347.564456 -270.945864)
		(width 0.088646)
		(layer "In11.Cu")
		(net "M_D_CPU0_SA_DQ<23>")
	)
	(segment
		(start 292.093396 -290.6903)
		(end 291.919152 -290.516056)
		(width 0.18288)
		(layer "In11.Cu")
		(net "M_D_CPU0_SA_DQ<23>")
	)
	(segment
		(start 276.634194 -290.555426)
		(end 275.559012 -290.555426)
		(width 0.18288)
		(layer "In11.Cu")
		(net "M_D_CPU0_SA_DQ<23>")
	)
	(segment
		(start 342.975946 -270.513302)
		(end 342.961214 -270.521938)
		(width 0.088646)
		(layer "In11.Cu")
		(net "M_D_CPU0_SA_DQ<23>")
	)
	(segment
		(start 304.951892 -287.91408)
		(end 304.951892 -288.336228)
		(width 0.18288)
		(layer "In11.Cu")
		(net "M_D_CPU0_SA_DQ<23>")
	)
	(segment
		(start 339.212428 -270.515842)
		(end 339.202014 -270.521938)
		(width 0.088646)
		(layer "In11.Cu")
		(net "M_D_CPU0_SA_DQ<23>")
	)
	(segment
		(start 333.375762 -270.572484)
		(end 332.620874 -270.572484)
		(width 0.088646)
		(layer "In11.Cu")
		(net "M_D_CPU0_SA_DQ<23>")
	)
	(segment
		(start 278.370792 -291.48151)
		(end 277.560278 -291.48151)
		(width 0.18288)
		(layer "In11.Cu")
		(net "M_D_CPU0_SA_DQ<23>")
	)
	(segment
		(start 298.761912 -289.560508)
		(end 298.042076 -289.858704)
		(width 0.18288)
		(layer "In11.Cu")
		(net "M_D_CPU0_SA_DQ<23>")
	)
	(segment
		(start 274.857972 -289.839908)
		(end 274.664932 -290.032948)
		(width 0.18288)
		(layer "In11.Cu")
		(net "M_D_CPU0_SA_DQ<23>")
	)
	(segment
		(start 290.929822 -290.709096)
		(end 290.929822 -291.040058)
		(width 0.18288)
		(layer "In11.Cu")
		(net "M_D_CPU0_SA_DQ<23>")
	)
	(segment
		(start 291.919152 -290.516056)
		(end 291.122862 -290.516056)
		(width 0.18288)
		(layer "In11.Cu")
		(net "M_D_CPU0_SA_DQ<23>")
	)
	(segment
		(start 271.764252 -289.705796)
		(end 271.40789 -289.349434)
		(width 0.18288)
		(layer "In11.Cu")
		(net "M_D_CPU0_SA_DQ<23>")
	)
	(arc
		(start 336.947764 -270.521938)
		(mid 336.665062 -270.446162)
		(end 336.38236 -270.521938)
		(width 0.088646)
		(layer "In11.Cu")
		(net "M_D_CPU0_SA_DQ<23>")
	)
	(arc
		(start 343.901014 -270.521938)
		(mid 343.713816 -270.572081)
		(end 343.526618 -270.521938)
		(width 0.088646)
		(layer "In11.Cu")
		(net "M_D_CPU0_SA_DQ<23>")
	)
	(arc
		(start 336.007964 -270.521938)
		(mid 335.725262 -270.446162)
		(end 335.44256 -270.521938)
		(width 0.088646)
		(layer "In11.Cu")
		(net "M_D_CPU0_SA_DQ<23>")
	)
	(arc
		(start 340.14156 -270.521938)
		(mid 339.954362 -270.572081)
		(end 339.767164 -270.521938)
		(width 0.088646)
		(layer "In11.Cu")
		(net "M_D_CPU0_SA_DQ<23>")
	)
	(arc
		(start 341.081614 -270.521938)
		(mid 340.894416 -270.572081)
		(end 340.707218 -270.521938)
		(width 0.088646)
		(layer "In11.Cu")
		(net "M_D_CPU0_SA_DQ<23>")
	)
	(arc
		(start 346.720414 -270.521938)
		(mid 346.53646 -270.572067)
		(end 346.351606 -270.52524)
		(width 0.088646)
		(layer "In11.Cu")
		(net "M_D_CPU0_SA_DQ<23>")
	)
	(arc
		(start 338.26196 -270.521938)
		(mid 338.074762 -270.572081)
		(end 337.887564 -270.521938)
		(width 0.088646)
		(layer "In11.Cu")
		(net "M_D_CPU0_SA_DQ<23>")
	)
	(arc
		(start 345.400122 -270.518636)
		(mid 345.120017 -270.446194)
		(end 344.840814 -270.521938)
		(width 0.088646)
		(layer "In11.Cu")
		(net "M_D_CPU0_SA_DQ<23>")
	)
	(arc
		(start 339.202014 -270.521938)
		(mid 339.014816 -270.572081)
		(end 338.827618 -270.521938)
		(width 0.088646)
		(layer "In11.Cu")
		(net "M_D_CPU0_SA_DQ<23>")
	)
	(arc
		(start 337.32216 -270.521938)
		(mid 337.134962 -270.572081)
		(end 336.947764 -270.521938)
		(width 0.088646)
		(layer "In11.Cu")
		(net "M_D_CPU0_SA_DQ<23>")
	)
	(arc
		(start 342.961214 -270.521938)
		(mid 342.774016 -270.572081)
		(end 342.586818 -270.521938)
		(width 0.088646)
		(layer "In11.Cu")
		(net "M_D_CPU0_SA_DQ<23>")
	)
	(arc
		(start 343.526618 -270.521938)
		(mid 343.252419 -270.446103)
		(end 342.975946 -270.513302)
		(width 0.088646)
		(layer "In11.Cu")
		(net "M_D_CPU0_SA_DQ<23>")
	)
	(arc
		(start 335.068164 -270.521938)
		(mid 334.785462 -270.446162)
		(end 334.50276 -270.521938)
		(width 0.088646)
		(layer "In11.Cu")
		(net "M_D_CPU0_SA_DQ<23>")
	)
	(arc
		(start 344.460322 -270.518636)
		(mid 344.180217 -270.446194)
		(end 343.901014 -270.521938)
		(width 0.088646)
		(layer "In11.Cu")
		(net "M_D_CPU0_SA_DQ<23>")
	)
	(arc
		(start 337.887564 -270.521938)
		(mid 337.604862 -270.446162)
		(end 337.32216 -270.521938)
		(width 0.088646)
		(layer "In11.Cu")
		(net "M_D_CPU0_SA_DQ<23>")
	)
	(arc
		(start 338.827618 -270.521938)
		(mid 338.550805 -270.446068)
		(end 338.272374 -270.515842)
		(width 0.088646)
		(layer "In11.Cu")
		(net "M_D_CPU0_SA_DQ<23>")
	)
	(arc
		(start 345.780614 -270.521938)
		(mid 345.59666 -270.572067)
		(end 345.411806 -270.52524)
		(width 0.088646)
		(layer "In11.Cu")
		(net "M_D_CPU0_SA_DQ<23>")
	)
	(arc
		(start 333.56296 -270.521938)
		(mid 333.472684 -270.559512)
		(end 333.375762 -270.572484)
		(width 0.088646)
		(layer "In11.Cu")
		(net "M_D_CPU0_SA_DQ<23>")
	)
	(arc
		(start 342.586818 -270.521938)
		(mid 342.304116 -270.446162)
		(end 342.021414 -270.521938)
		(width 0.088646)
		(layer "In11.Cu")
		(net "M_D_CPU0_SA_DQ<23>")
	)
	(arc
		(start 342.021414 -270.521938)
		(mid 341.834216 -270.572081)
		(end 341.647018 -270.521938)
		(width 0.088646)
		(layer "In11.Cu")
		(net "M_D_CPU0_SA_DQ<23>")
	)
	(arc
		(start 336.38236 -270.521938)
		(mid 336.195162 -270.572081)
		(end 336.007964 -270.521938)
		(width 0.088646)
		(layer "In11.Cu")
		(net "M_D_CPU0_SA_DQ<23>")
	)
	(arc
		(start 334.50276 -270.521938)
		(mid 334.315562 -270.572081)
		(end 334.128364 -270.521938)
		(width 0.088646)
		(layer "In11.Cu")
		(net "M_D_CPU0_SA_DQ<23>")
	)
	(arc
		(start 341.647018 -270.521938)
		(mid 341.372819 -270.446103)
		(end 341.096346 -270.513302)
		(width 0.088646)
		(layer "In11.Cu")
		(net "M_D_CPU0_SA_DQ<23>")
	)
	(arc
		(start 347.564456 -270.945864)
		(mid 347.47586 -270.701902)
		(end 347.287596 -270.523208)
		(width 0.088646)
		(layer "In11.Cu")
		(net "M_D_CPU0_SA_DQ<23>")
	)
	(arc
		(start 339.767164 -270.521938)
		(mid 339.490605 -270.446195)
		(end 339.212428 -270.515842)
		(width 0.088646)
		(layer "In11.Cu")
		(net "M_D_CPU0_SA_DQ<23>")
	)
	(arc
		(start 347.279722 -270.518636)
		(mid 346.999617 -270.446194)
		(end 346.720414 -270.521938)
		(width 0.088646)
		(layer "In11.Cu")
		(net "M_D_CPU0_SA_DQ<23>")
	)
	(arc
		(start 340.707218 -270.521938)
		(mid 340.430405 -270.446068)
		(end 340.151974 -270.515842)
		(width 0.088646)
		(layer "In11.Cu")
		(net "M_D_CPU0_SA_DQ<23>")
	)
	(arc
		(start 335.44256 -270.521938)
		(mid 335.255362 -270.572081)
		(end 335.068164 -270.521938)
		(width 0.088646)
		(layer "In11.Cu")
		(net "M_D_CPU0_SA_DQ<23>")
	)
	(arc
		(start 346.339922 -270.518636)
		(mid 346.059817 -270.446194)
		(end 345.780614 -270.521938)
		(width 0.088646)
		(layer "In11.Cu")
		(net "M_D_CPU0_SA_DQ<23>")
	)
	(arc
		(start 344.840814 -270.521938)
		(mid 344.65686 -270.572067)
		(end 344.472006 -270.52524)
		(width 0.088646)
		(layer "In11.Cu")
		(net "M_D_CPU0_SA_DQ<23>")
	)
	(arc
		(start 334.128364 -270.521938)
		(mid 333.845662 -270.446162)
		(end 333.56296 -270.521938)
		(width 0.088646)
		(layer "In11.Cu")
		(net "M_D_CPU0_SA_DQ<23>")
	)
	(segment
		(start 264.825226 -290.39185)
		(end 262.765286 -290.39185)
		(width 0.1016)
		(layer "F.Cu")
		(net "M_D_CPU0_SA_DQ<22>")
	)
	(segment
		(start 348.412562 -271.289272)
		(end 348.412816 -271.289526)
		(width 0.20066)
		(layer "F.Cu")
		(net "M_D_CPU0_SA_DQ<22>")
	)
	(segment
		(start 262.765286 -290.39185)
		(end 262.51027 -290.39185)
		(width 0.101854)
		(layer "F.Cu")
		(net "M_D_CPU0_SA_DQ<22>")
	)
	(segment
		(start 267.724382 -290.816792)
		(end 266.409678 -290.816792)
		(width 0.20066)
		(layer "F.Cu")
		(net "M_D_CPU0_SA_DQ<22>")
	)
	(segment
		(start 261.327646 -290.816792)
		(end 260.180582 -290.816792)
		(width 0.20066)
		(layer "F.Cu")
		(net "M_D_CPU0_SA_DQ<22>")
	)
	(segment
		(start 266.409678 -290.816792)
		(end 266.197842 -291.028628)
		(width 0.20066)
		(layer "F.Cu")
		(net "M_D_CPU0_SA_DQ<22>")
	)
	(segment
		(start 265.601958 -290.535614)
		(end 265.458194 -290.39185)
		(width 0.20066)
		(layer "F.Cu")
		(net "M_D_CPU0_SA_DQ<22>")
	)
	(segment
		(start 262.51027 -290.39185)
		(end 262.50011 -290.38169)
		(width 0.101854)
		(layer "F.Cu")
		(net "M_D_CPU0_SA_DQ<22>")
	)
	(segment
		(start 268.829282 -290.816792)
		(end 267.724382 -290.816792)
		(width 0.20066)
		(layer "F.Cu")
		(net "M_D_CPU0_SA_DQ<22>")
	)
	(segment
		(start 265.601958 -290.861242)
		(end 265.601958 -290.535614)
		(width 0.20066)
		(layer "F.Cu")
		(net "M_D_CPU0_SA_DQ<22>")
	)
	(segment
		(start 262.50011 -290.38169)
		(end 261.762748 -290.38169)
		(width 0.20066)
		(layer "F.Cu")
		(net "M_D_CPU0_SA_DQ<22>")
	)
	(segment
		(start 265.458194 -290.39185)
		(end 264.825226 -290.39185)
		(width 0.20066)
		(layer "F.Cu")
		(net "M_D_CPU0_SA_DQ<22>")
	)
	(segment
		(start 265.769344 -291.028628)
		(end 265.601958 -290.861242)
		(width 0.20066)
		(layer "F.Cu")
		(net "M_D_CPU0_SA_DQ<22>")
	)
	(segment
		(start 261.762748 -290.38169)
		(end 261.327646 -290.816792)
		(width 0.20066)
		(layer "F.Cu")
		(net "M_D_CPU0_SA_DQ<22>")
	)
	(segment
		(start 266.197842 -291.028628)
		(end 265.769344 -291.028628)
		(width 0.20066)
		(layer "F.Cu")
		(net "M_D_CPU0_SA_DQ<22>")
	)
	(segment
		(start 348.412816 -271.289526)
		(end 348.412816 -271.825212)
		(width 0.20066)
		(layer "F.Cu")
		(net "M_D_CPU0_SA_DQ<22>")
	)
	(segment
		(start 271.401032 -291.00526)
		(end 271.207992 -290.81222)
		(width 0.18288)
		(layer "In11.Cu")
		(net "M_D_CPU0_SA_DQ<22>")
	)
	(segment
		(start 332.467712 -271.3863)
		(end 332.02499 -271.829022)
		(width 0.088646)
		(layer "In11.Cu")
		(net "M_D_CPU0_SA_DQ<22>")
	)
	(segment
		(start 280.931112 -292.328854)
		(end 280.497026 -292.328854)
		(width 0.18288)
		(layer "In11.Cu")
		(net "M_D_CPU0_SA_DQ<22>")
	)
	(segment
		(start 285.79699 -291.089588)
		(end 285.60395 -291.282628)
		(width 0.18288)
		(layer "In11.Cu")
		(net "M_D_CPU0_SA_DQ<22>")
	)
	(segment
		(start 274.89277 -292.012624)
		(end 274.69973 -292.205664)
		(width 0.18288)
		(layer "In11.Cu")
		(net "M_D_CPU0_SA_DQ<22>")
	)
	(segment
		(start 310.41467 -287.829244)
		(end 310.41467 -288.367978)
		(width 0.18288)
		(layer "In11.Cu")
		(net "M_D_CPU0_SA_DQ<22>")
	)
	(segment
		(start 296.267886 -292.319456)
		(end 296.04081 -292.09238)
		(width 0.18288)
		(layer "In11.Cu")
		(net "M_D_CPU0_SA_DQ<22>")
	)
	(segment
		(start 286.69107 -291.282628)
		(end 286.49803 -291.089588)
		(width 0.18288)
		(layer "In11.Cu")
		(net "M_D_CPU0_SA_DQ<22>")
	)
	(segment
		(start 347.196156 -271.332452)
		(end 347.190314 -271.335754)
		(width 0.088646)
		(layer "In11.Cu")
		(net "M_D_CPU0_SA_DQ<22>")
	)
	(segment
		(start 304.411126 -290.530026)
		(end 303.697894 -290.530026)
		(width 0.18288)
		(layer "In11.Cu")
		(net "M_D_CPU0_SA_DQ<22>")
	)
	(segment
		(start 343.056464 -271.335754)
		(end 343.04605 -271.329658)
		(width 0.088646)
		(layer "In11.Cu")
		(net "M_D_CPU0_SA_DQ<22>")
	)
	(segment
		(start 347.190314 -271.335754)
		(end 347.184472 -271.33931)
		(width 0.088646)
		(layer "In11.Cu")
		(net "M_D_CPU0_SA_DQ<22>")
	)
	(segment
		(start 277.23338 -293.081456)
		(end 276.357588 -292.205664)
		(width 0.18288)
		(layer "In11.Cu")
		(net "M_D_CPU0_SA_DQ<22>")
	)
	(segment
		(start 340.237064 -271.335754)
		(end 340.222332 -271.327118)
		(width 0.088646)
		(layer "In11.Cu")
		(net "M_D_CPU0_SA_DQ<22>")
	)
	(segment
		(start 309.070248 -287.537652)
		(end 308.86908 -287.73882)
		(width 0.18288)
		(layer "In11.Cu")
		(net "M_D_CPU0_SA_DQ<22>")
	)
	(segment
		(start 331.822552 -273.333464)
		(end 331.392022 -273.763994)
		(width 0.088646)
		(layer "In11.Cu")
		(net "M_D_CPU0_SA_DQ<22>")
	)
	(segment
		(start 274.89277 -291.855906)
		(end 274.89277 -292.012624)
		(width 0.18288)
		(layer "In11.Cu")
		(net "M_D_CPU0_SA_DQ<22>")
	)
	(segment
		(start 342.116918 -271.335754)
		(end 342.106504 -271.329658)
		(width 0.088646)
		(layer "In11.Cu")
		(net "M_D_CPU0_SA_DQ<22>")
	)
	(segment
		(start 270.893032 -290.81222)
		(end 270.699992 -291.00526)
		(width 0.18288)
		(layer "In11.Cu")
		(net "M_D_CPU0_SA_DQ<22>")
	)
	(segment
		(start 281.601672 -292.09238)
		(end 281.167586 -292.09238)
		(width 0.18288)
		(layer "In11.Cu")
		(net "M_D_CPU0_SA_DQ<22>")
	)
	(segment
		(start 284.639258 -291.282628)
		(end 284.598872 -291.242242)
		(width 0.18288)
		(layer "In11.Cu")
		(net "M_D_CPU0_SA_DQ<22>")
	)
	(segment
		(start 347.835982 -271.38249)
		(end 347.755464 -271.336008)
		(width 0.088646)
		(layer "In11.Cu")
		(net "M_D_CPU0_SA_DQ<22>")
	)
	(segment
		(start 283.4767 -291.242242)
		(end 282.390088 -292.328854)
		(width 0.18288)
		(layer "In11.Cu")
		(net "M_D_CPU0_SA_DQ<22>")
	)
	(segment
		(start 275.40077 -291.662866)
		(end 275.08581 -291.662866)
		(width 0.18288)
		(layer "In11.Cu")
		(net "M_D_CPU0_SA_DQ<22>")
	)
	(segment
		(start 275.59381 -292.012624)
		(end 275.59381 -291.855906)
		(width 0.18288)
		(layer "In11.Cu")
		(net "M_D_CPU0_SA_DQ<22>")
	)
	(segment
		(start 285.99003 -290.820856)
		(end 285.79699 -291.013896)
		(width 0.18288)
		(layer "In11.Cu")
		(net "M_D_CPU0_SA_DQ<22>")
	)
	(segment
		(start 331.822552 -272.376646)
		(end 331.822552 -273.333464)
		(width 0.088646)
		(layer "In11.Cu")
		(net "M_D_CPU0_SA_DQ<22>")
	)
	(segment
		(start 302.83404 -291.39388)
		(end 299.876464 -291.39388)
		(width 0.18288)
		(layer "In11.Cu")
		(net "M_D_CPU0_SA_DQ<22>")
	)
	(segment
		(start 282.390088 -292.328854)
		(end 281.838146 -292.328854)
		(width 0.18288)
		(layer "In11.Cu")
		(net "M_D_CPU0_SA_DQ<22>")
	)
	(segment
		(start 309.738268 -288.574226)
		(end 309.578248 -288.414206)
		(width 0.18288)
		(layer "In11.Cu")
		(net "M_D_CPU0_SA_DQ<22>")
	)
	(segment
		(start 332.905862 -271.3863)
		(end 332.467712 -271.3863)
		(width 0.088646)
		(layer "In11.Cu")
		(net "M_D_CPU0_SA_DQ<22>")
	)
	(segment
		(start 271.594072 -291.337238)
		(end 271.401032 -291.144198)
		(width 0.18288)
		(layer "In11.Cu")
		(net "M_D_CPU0_SA_DQ<22>")
	)
	(segment
		(start 298.30903 -291.242242)
		(end 297.458892 -292.09238)
		(width 0.18288)
		(layer "In11.Cu")
		(net "M_D_CPU0_SA_DQ<22>")
	)
	(segment
		(start 291.307774 -292.993826)
		(end 290.596574 -292.282626)
		(width 0.18288)
		(layer "In11.Cu")
		(net "M_D_CPU0_SA_DQ<22>")
	)
	(segment
		(start 288.711894 -292.282626)
		(end 287.711896 -291.282628)
		(width 0.18288)
		(layer "In11.Cu")
		(net "M_D_CPU0_SA_DQ<22>")
	)
	(segment
		(start 306.163726 -288.777426)
		(end 304.411126 -290.530026)
		(width 0.18288)
		(layer "In11.Cu")
		(net "M_D_CPU0_SA_DQ<22>")
	)
	(segment
		(start 310.208422 -288.574226)
		(end 309.738268 -288.574226)
		(width 0.18288)
		(layer "In11.Cu")
		(net "M_D_CPU0_SA_DQ<22>")
	)
	(segment
		(start 299.724826 -291.242242)
		(end 298.30903 -291.242242)
		(width 0.18288)
		(layer "In11.Cu")
		(net "M_D_CPU0_SA_DQ<22>")
	)
	(segment
		(start 309.578248 -288.414206)
		(end 309.578248 -287.697672)
		(width 0.18288)
		(layer "In11.Cu")
		(net "M_D_CPU0_SA_DQ<22>")
	)
	(segment
		(start 344.371422 -271.335754)
		(end 344.37066 -271.335754)
		(width 0.088646)
		(layer "In11.Cu")
		(net "M_D_CPU0_SA_DQ<22>")
	)
	(segment
		(start 285.60395 -291.282628)
		(end 284.639258 -291.282628)
		(width 0.18288)
		(layer "In11.Cu")
		(net "M_D_CPU0_SA_DQ<22>")
	)
	(segment
		(start 309.418228 -287.537652)
		(end 309.070248 -287.537652)
		(width 0.18288)
		(layer "In11.Cu")
		(net "M_D_CPU0_SA_DQ<22>")
	)
	(segment
		(start 270.699992 -291.144198)
		(end 270.506952 -291.337238)
		(width 0.18288)
		(layer "In11.Cu")
		(net "M_D_CPU0_SA_DQ<22>")
	)
	(segment
		(start 280.497026 -292.328854)
		(end 280.260552 -292.09238)
		(width 0.18288)
		(layer "In11.Cu")
		(net "M_D_CPU0_SA_DQ<22>")
	)
	(segment
		(start 269.349728 -291.337238)
		(end 268.829282 -290.816792)
		(width 0.18288)
		(layer "In11.Cu")
		(net "M_D_CPU0_SA_DQ<22>")
	)
	(segment
		(start 308.70906 -288.574226)
		(end 307.076094 -288.574226)
		(width 0.18288)
		(layer "In11.Cu")
		(net "M_D_CPU0_SA_DQ<22>")
	)
	(segment
		(start 314.456572 -287.115758)
		(end 311.128156 -287.115758)
		(width 0.18288)
		(layer "In11.Cu")
		(net "M_D_CPU0_SA_DQ<22>")
	)
	(segment
		(start 284.598872 -291.242242)
		(end 283.4767 -291.242242)
		(width 0.18288)
		(layer "In11.Cu")
		(net "M_D_CPU0_SA_DQ<22>")
	)
	(segment
		(start 296.938446 -292.09238)
		(end 296.71137 -292.319456)
		(width 0.18288)
		(layer "In11.Cu")
		(net "M_D_CPU0_SA_DQ<22>")
	)
	(segment
		(start 346.256356 -271.332452)
		(end 346.250514 -271.335754)
		(width 0.088646)
		(layer "In11.Cu")
		(net "M_D_CPU0_SA_DQ<22>")
	)
	(segment
		(start 345.316556 -271.332452)
		(end 345.289632 -271.347438)
		(width 0.088646)
		(layer "In11.Cu")
		(net "M_D_CPU0_SA_DQ<22>")
	)
	(segment
		(start 299.876464 -291.39388)
		(end 299.724826 -291.242242)
		(width 0.18288)
		(layer "In11.Cu")
		(net "M_D_CPU0_SA_DQ<22>")
	)
	(segment
		(start 346.250514 -271.335754)
		(end 346.244672 -271.33931)
		(width 0.088646)
		(layer "In11.Cu")
		(net "M_D_CPU0_SA_DQ<22>")
	)
	(segment
		(start 274.69973 -292.205664)
		(end 274.205954 -292.205664)
		(width 0.18288)
		(layer "In11.Cu")
		(net "M_D_CPU0_SA_DQ<22>")
	)
	(segment
		(start 293.399718 -292.993826)
		(end 291.307774 -292.993826)
		(width 0.18288)
		(layer "In11.Cu")
		(net "M_D_CPU0_SA_DQ<22>")
	)
	(segment
		(start 275.08581 -291.662866)
		(end 274.89277 -291.855906)
		(width 0.18288)
		(layer "In11.Cu")
		(net "M_D_CPU0_SA_DQ<22>")
	)
	(segment
		(start 281.167586 -292.09238)
		(end 280.931112 -292.328854)
		(width 0.18288)
		(layer "In11.Cu")
		(net "M_D_CPU0_SA_DQ<22>")
	)
	(segment
		(start 271.401032 -291.144198)
		(end 271.401032 -291.00526)
		(width 0.18288)
		(layer "In11.Cu")
		(net "M_D_CPU0_SA_DQ<22>")
	)
	(segment
		(start 271.207992 -290.81222)
		(end 270.893032 -290.81222)
		(width 0.18288)
		(layer "In11.Cu")
		(net "M_D_CPU0_SA_DQ<22>")
	)
	(segment
		(start 343.996264 -271.335754)
		(end 343.981532 -271.327118)
		(width 0.088646)
		(layer "In11.Cu")
		(net "M_D_CPU0_SA_DQ<22>")
	)
	(segment
		(start 297.458892 -292.09238)
		(end 296.938446 -292.09238)
		(width 0.18288)
		(layer "In11.Cu")
		(net "M_D_CPU0_SA_DQ<22>")
	)
	(segment
		(start 275.78685 -292.205664)
		(end 275.59381 -292.012624)
		(width 0.18288)
		(layer "In11.Cu")
		(net "M_D_CPU0_SA_DQ<22>")
	)
	(segment
		(start 285.79699 -291.013896)
		(end 285.79699 -291.089588)
		(width 0.18288)
		(layer "In11.Cu")
		(net "M_D_CPU0_SA_DQ<22>")
	)
	(segment
		(start 308.86908 -287.73882)
		(end 308.86908 -288.414206)
		(width 0.18288)
		(layer "In11.Cu")
		(net "M_D_CPU0_SA_DQ<22>")
	)
	(segment
		(start 307.076094 -288.574226)
		(end 306.872894 -288.777426)
		(width 0.18288)
		(layer "In11.Cu")
		(net "M_D_CPU0_SA_DQ<22>")
	)
	(segment
		(start 281.838146 -292.328854)
		(end 281.601672 -292.09238)
		(width 0.18288)
		(layer "In11.Cu")
		(net "M_D_CPU0_SA_DQ<22>")
	)
	(segment
		(start 341.176864 -271.335754)
		(end 341.162132 -271.327118)
		(width 0.088646)
		(layer "In11.Cu")
		(net "M_D_CPU0_SA_DQ<22>")
	)
	(segment
		(start 294.301164 -292.09238)
		(end 293.399718 -292.993826)
		(width 0.18288)
		(layer "In11.Cu")
		(net "M_D_CPU0_SA_DQ<22>")
	)
	(segment
		(start 290.596574 -292.282626)
		(end 288.711894 -292.282626)
		(width 0.18288)
		(layer "In11.Cu")
		(net "M_D_CPU0_SA_DQ<22>")
	)
	(segment
		(start 273.116802 -291.337238)
		(end 271.594072 -291.337238)
		(width 0.18288)
		(layer "In11.Cu")
		(net "M_D_CPU0_SA_DQ<22>")
	)
	(segment
		(start 331.004926 -273.763994)
		(end 327.808336 -273.763994)
		(width 0.18288)
		(layer "In11.Cu")
		(net "M_D_CPU0_SA_DQ<22>")
	)
	(segment
		(start 287.711896 -291.282628)
		(end 286.69107 -291.282628)
		(width 0.18288)
		(layer "In11.Cu")
		(net "M_D_CPU0_SA_DQ<22>")
	)
	(segment
		(start 280.260552 -292.09238)
		(end 279.29205 -292.09238)
		(width 0.18288)
		(layer "In11.Cu")
		(net "M_D_CPU0_SA_DQ<22>")
	)
	(segment
		(start 276.357588 -292.205664)
		(end 275.78685 -292.205664)
		(width 0.18288)
		(layer "In11.Cu")
		(net "M_D_CPU0_SA_DQ<22>")
	)
	(segment
		(start 303.697894 -290.530026)
		(end 302.83404 -291.39388)
		(width 0.18288)
		(layer "In11.Cu")
		(net "M_D_CPU0_SA_DQ<22>")
	)
	(segment
		(start 332.02499 -272.174208)
		(end 331.822552 -272.376646)
		(width 0.088646)
		(layer "In11.Cu")
		(net "M_D_CPU0_SA_DQ<22>")
	)
	(segment
		(start 278.302974 -293.081456)
		(end 277.23338 -293.081456)
		(width 0.18288)
		(layer "In11.Cu")
		(net "M_D_CPU0_SA_DQ<22>")
	)
	(segment
		(start 332.02499 -271.829022)
		(end 332.02499 -272.174208)
		(width 0.088646)
		(layer "In11.Cu")
		(net "M_D_CPU0_SA_DQ<22>")
	)
	(segment
		(start 308.86908 -288.414206)
		(end 308.70906 -288.574226)
		(width 0.18288)
		(layer "In11.Cu")
		(net "M_D_CPU0_SA_DQ<22>")
	)
	(segment
		(start 270.699992 -291.00526)
		(end 270.699992 -291.144198)
		(width 0.18288)
		(layer "In11.Cu")
		(net "M_D_CPU0_SA_DQ<22>")
	)
	(segment
		(start 296.04081 -292.09238)
		(end 294.301164 -292.09238)
		(width 0.18288)
		(layer "In11.Cu")
		(net "M_D_CPU0_SA_DQ<22>")
	)
	(segment
		(start 274.205954 -292.205664)
		(end 273.829018 -292.049454)
		(width 0.18288)
		(layer "In11.Cu")
		(net "M_D_CPU0_SA_DQ<22>")
	)
	(segment
		(start 286.30499 -290.820856)
		(end 285.99003 -290.820856)
		(width 0.18288)
		(layer "In11.Cu")
		(net "M_D_CPU0_SA_DQ<22>")
	)
	(segment
		(start 306.872894 -288.777426)
		(end 306.163726 -288.777426)
		(width 0.18288)
		(layer "In11.Cu")
		(net "M_D_CPU0_SA_DQ<22>")
	)
	(segment
		(start 275.59381 -291.855906)
		(end 275.40077 -291.662866)
		(width 0.18288)
		(layer "In11.Cu")
		(net "M_D_CPU0_SA_DQ<22>")
	)
	(segment
		(start 279.29205 -292.09238)
		(end 278.302974 -293.081456)
		(width 0.18288)
		(layer "In11.Cu")
		(net "M_D_CPU0_SA_DQ<22>")
	)
	(segment
		(start 327.808336 -273.763994)
		(end 314.456572 -287.115758)
		(width 0.18288)
		(layer "In11.Cu")
		(net "M_D_CPU0_SA_DQ<22>")
	)
	(segment
		(start 310.41467 -288.367978)
		(end 310.208422 -288.574226)
		(width 0.18288)
		(layer "In11.Cu")
		(net "M_D_CPU0_SA_DQ<22>")
	)
	(segment
		(start 337.417664 -271.335754)
		(end 337.402932 -271.327118)
		(width 0.088646)
		(layer "In11.Cu")
		(net "M_D_CPU0_SA_DQ<22>")
	)
	(segment
		(start 309.578248 -287.697672)
		(end 309.418228 -287.537652)
		(width 0.18288)
		(layer "In11.Cu")
		(net "M_D_CPU0_SA_DQ<22>")
	)
	(segment
		(start 273.829018 -292.049454)
		(end 273.116802 -291.337238)
		(width 0.18288)
		(layer "In11.Cu")
		(net "M_D_CPU0_SA_DQ<22>")
	)
	(segment
		(start 270.506952 -291.337238)
		(end 269.349728 -291.337238)
		(width 0.18288)
		(layer "In11.Cu")
		(net "M_D_CPU0_SA_DQ<22>")
	)
	(segment
		(start 286.49803 -291.013896)
		(end 286.30499 -290.820856)
		(width 0.18288)
		(layer "In11.Cu")
		(net "M_D_CPU0_SA_DQ<22>")
	)
	(segment
		(start 311.128156 -287.115758)
		(end 310.41467 -287.829244)
		(width 0.18288)
		(layer "In11.Cu")
		(net "M_D_CPU0_SA_DQ<22>")
	)
	(segment
		(start 296.71137 -292.319456)
		(end 296.267886 -292.319456)
		(width 0.18288)
		(layer "In11.Cu")
		(net "M_D_CPU0_SA_DQ<22>")
	)
	(segment
		(start 286.49803 -291.089588)
		(end 286.49803 -291.013896)
		(width 0.18288)
		(layer "In11.Cu")
		(net "M_D_CPU0_SA_DQ<22>")
	)
	(segment
		(start 331.392022 -273.763994)
		(end 331.004926 -273.763994)
		(width 0.088646)
		(layer "In11.Cu")
		(net "M_D_CPU0_SA_DQ<22>")
	)
	(arc
		(start 344.936064 -271.336008)
		(mid 344.653789 -271.260325)
		(end 344.371422 -271.335754)
		(width 0.088646)
		(layer "In11.Cu")
		(net "M_D_CPU0_SA_DQ<22>")
	)
	(arc
		(start 337.402932 -271.327118)
		(mid 337.126457 -271.259798)
		(end 336.85226 -271.335754)
		(width 0.088646)
		(layer "In11.Cu")
		(net "M_D_CPU0_SA_DQ<22>")
	)
	(arc
		(start 342.106504 -271.329658)
		(mid 341.828072 -271.259812)
		(end 341.55126 -271.335754)
		(width 0.088646)
		(layer "In11.Cu")
		(net "M_D_CPU0_SA_DQ<22>")
	)
	(arc
		(start 340.222332 -271.327118)
		(mid 339.945857 -271.259798)
		(end 339.67166 -271.335754)
		(width 0.088646)
		(layer "In11.Cu")
		(net "M_D_CPU0_SA_DQ<22>")
	)
	(arc
		(start 333.09306 -271.335754)
		(mid 333.002788 -271.373353)
		(end 332.905862 -271.3863)
		(width 0.088646)
		(layer "In11.Cu")
		(net "M_D_CPU0_SA_DQ<22>")
	)
	(arc
		(start 336.85226 -271.335754)
		(mid 336.665062 -271.385897)
		(end 336.477864 -271.335754)
		(width 0.088646)
		(layer "In11.Cu")
		(net "M_D_CPU0_SA_DQ<22>")
	)
	(arc
		(start 347.184472 -271.33931)
		(mid 346.999617 -271.386228)
		(end 346.815664 -271.336008)
		(width 0.088646)
		(layer "In11.Cu")
		(net "M_D_CPU0_SA_DQ<22>")
	)
	(arc
		(start 334.598264 -271.335754)
		(mid 334.315562 -271.259978)
		(end 334.03286 -271.335754)
		(width 0.088646)
		(layer "In11.Cu")
		(net "M_D_CPU0_SA_DQ<22>")
	)
	(arc
		(start 339.297264 -271.335754)
		(mid 339.014562 -271.259978)
		(end 338.73186 -271.335754)
		(width 0.088646)
		(layer "In11.Cu")
		(net "M_D_CPU0_SA_DQ<22>")
	)
	(arc
		(start 343.981532 -271.327118)
		(mid 343.705057 -271.259798)
		(end 343.43086 -271.335754)
		(width 0.088646)
		(layer "In11.Cu")
		(net "M_D_CPU0_SA_DQ<22>")
	)
	(arc
		(start 338.73186 -271.335754)
		(mid 338.544662 -271.385897)
		(end 338.357464 -271.335754)
		(width 0.088646)
		(layer "In11.Cu")
		(net "M_D_CPU0_SA_DQ<22>")
	)
	(arc
		(start 341.55126 -271.335754)
		(mid 341.364062 -271.385897)
		(end 341.176864 -271.335754)
		(width 0.088646)
		(layer "In11.Cu")
		(net "M_D_CPU0_SA_DQ<22>")
	)
	(arc
		(start 335.91246 -271.335754)
		(mid 335.725262 -271.385897)
		(end 335.538064 -271.335754)
		(width 0.088646)
		(layer "In11.Cu")
		(net "M_D_CPU0_SA_DQ<22>")
	)
	(arc
		(start 336.477864 -271.335754)
		(mid 336.195162 -271.259978)
		(end 335.91246 -271.335754)
		(width 0.088646)
		(layer "In11.Cu")
		(net "M_D_CPU0_SA_DQ<22>")
	)
	(arc
		(start 347.755464 -271.336008)
		(mid 347.47629 -271.260209)
		(end 347.196156 -271.332452)
		(width 0.088646)
		(layer "In11.Cu")
		(net "M_D_CPU0_SA_DQ<22>")
	)
	(arc
		(start 333.658464 -271.335754)
		(mid 333.375762 -271.259978)
		(end 333.09306 -271.335754)
		(width 0.088646)
		(layer "In11.Cu")
		(net "M_D_CPU0_SA_DQ<22>")
	)
	(arc
		(start 345.289632 -271.347438)
		(mid 345.111413 -271.386059)
		(end 344.936064 -271.336008)
		(width 0.088646)
		(layer "In11.Cu")
		(net "M_D_CPU0_SA_DQ<22>")
	)
	(arc
		(start 335.538064 -271.335754)
		(mid 335.255362 -271.259978)
		(end 334.97266 -271.335754)
		(width 0.088646)
		(layer "In11.Cu")
		(net "M_D_CPU0_SA_DQ<22>")
	)
	(arc
		(start 343.43086 -271.335754)
		(mid 343.243662 -271.385897)
		(end 343.056464 -271.335754)
		(width 0.088646)
		(layer "In11.Cu")
		(net "M_D_CPU0_SA_DQ<22>")
	)
	(arc
		(start 339.67166 -271.335754)
		(mid 339.484462 -271.385897)
		(end 339.297264 -271.335754)
		(width 0.088646)
		(layer "In11.Cu")
		(net "M_D_CPU0_SA_DQ<22>")
	)
	(arc
		(start 334.03286 -271.335754)
		(mid 333.845662 -271.385897)
		(end 333.658464 -271.335754)
		(width 0.088646)
		(layer "In11.Cu")
		(net "M_D_CPU0_SA_DQ<22>")
	)
	(arc
		(start 337.79206 -271.335754)
		(mid 337.604862 -271.385897)
		(end 337.417664 -271.335754)
		(width 0.088646)
		(layer "In11.Cu")
		(net "M_D_CPU0_SA_DQ<22>")
	)
	(arc
		(start 341.162132 -271.327118)
		(mid 340.885657 -271.259798)
		(end 340.61146 -271.335754)
		(width 0.088646)
		(layer "In11.Cu")
		(net "M_D_CPU0_SA_DQ<22>")
	)
	(arc
		(start 343.04605 -271.329658)
		(mid 342.767872 -271.259935)
		(end 342.491314 -271.335754)
		(width 0.088646)
		(layer "In11.Cu")
		(net "M_D_CPU0_SA_DQ<22>")
	)
	(arc
		(start 348.412816 -271.825212)
		(mid 348.138858 -271.585013)
		(end 347.835982 -271.38249)
		(width 0.088646)
		(layer "In11.Cu")
		(net "M_D_CPU0_SA_DQ<22>")
	)
	(arc
		(start 346.244672 -271.33931)
		(mid 346.059817 -271.386228)
		(end 345.875864 -271.336008)
		(width 0.088646)
		(layer "In11.Cu")
		(net "M_D_CPU0_SA_DQ<22>")
	)
	(arc
		(start 340.61146 -271.335754)
		(mid 340.424262 -271.385897)
		(end 340.237064 -271.335754)
		(width 0.088646)
		(layer "In11.Cu")
		(net "M_D_CPU0_SA_DQ<22>")
	)
	(arc
		(start 342.491314 -271.335754)
		(mid 342.304116 -271.385897)
		(end 342.116918 -271.335754)
		(width 0.088646)
		(layer "In11.Cu")
		(net "M_D_CPU0_SA_DQ<22>")
	)
	(arc
		(start 334.97266 -271.335754)
		(mid 334.785462 -271.385897)
		(end 334.598264 -271.335754)
		(width 0.088646)
		(layer "In11.Cu")
		(net "M_D_CPU0_SA_DQ<22>")
	)
	(arc
		(start 345.875864 -271.336008)
		(mid 345.59669 -271.260209)
		(end 345.316556 -271.332452)
		(width 0.088646)
		(layer "In11.Cu")
		(net "M_D_CPU0_SA_DQ<22>")
	)
	(arc
		(start 346.815664 -271.336008)
		(mid 346.53649 -271.260209)
		(end 346.256356 -271.332452)
		(width 0.088646)
		(layer "In11.Cu")
		(net "M_D_CPU0_SA_DQ<22>")
	)
	(arc
		(start 344.37066 -271.335754)
		(mid 344.183462 -271.385897)
		(end 343.996264 -271.335754)
		(width 0.088646)
		(layer "In11.Cu")
		(net "M_D_CPU0_SA_DQ<22>")
	)
	(arc
		(start 338.357464 -271.335754)
		(mid 338.074762 -271.259978)
		(end 337.79206 -271.335754)
		(width 0.088646)
		(layer "In11.Cu")
		(net "M_D_CPU0_SA_DQ<22>")
	)
	(segment
		(start 261.560056 -289.541712)
		(end 261.381494 -289.541712)
		(width 0.20066)
		(layer "F.Cu")
		(net "M_D_CPU0_SA_DQ<21>")
	)
	(segment
		(start 264.729214 -289.966654)
		(end 263.624314 -289.966654)
		(width 0.20066)
		(layer "F.Cu")
		(net "M_D_CPU0_SA_DQ<21>")
	)
	(segment
		(start 259.065268 -289.541712)
		(end 259.056378 -289.532822)
		(width 0.1016)
		(layer "F.Cu")
		(net "M_D_CPU0_SA_DQ<21>")
	)
	(segment
		(start 258.44754 -289.532822)
		(end 258.28498 -289.695382)
		(width 0.20066)
		(layer "F.Cu")
		(net "M_D_CPU0_SA_DQ<21>")
	)
	(segment
		(start 257.414776 -289.966654)
		(end 256.080514 -289.966654)
		(width 0.20066)
		(layer "F.Cu")
		(net "M_D_CPU0_SA_DQ<21>")
	)
	(segment
		(start 263.624314 -289.966654)
		(end 261.984998 -289.966654)
		(width 0.20066)
		(layer "F.Cu")
		(net "M_D_CPU0_SA_DQ<21>")
	)
	(segment
		(start 261.381494 -289.541712)
		(end 261.050786 -289.541712)
		(width 0.101854)
		(layer "F.Cu")
		(net "M_D_CPU0_SA_DQ<21>")
	)
	(segment
		(start 258.28498 -289.695382)
		(end 258.28498 -290.02355)
		(width 0.20066)
		(layer "F.Cu")
		(net "M_D_CPU0_SA_DQ<21>")
	)
	(segment
		(start 261.984998 -289.966654)
		(end 261.560056 -289.541712)
		(width 0.20066)
		(layer "F.Cu")
		(net "M_D_CPU0_SA_DQ<21>")
	)
	(segment
		(start 258.28498 -290.02355)
		(end 258.130548 -290.177982)
		(width 0.20066)
		(layer "F.Cu")
		(net "M_D_CPU0_SA_DQ<21>")
	)
	(segment
		(start 261.050786 -289.541712)
		(end 259.065268 -289.541712)
		(width 0.1016)
		(layer "F.Cu")
		(net "M_D_CPU0_SA_DQ<21>")
	)
	(segment
		(start 259.056378 -289.532822)
		(end 258.44754 -289.532822)
		(width 0.20066)
		(layer "F.Cu")
		(net "M_D_CPU0_SA_DQ<21>")
	)
	(segment
		(start 257.626104 -290.177982)
		(end 257.414776 -289.966654)
		(width 0.20066)
		(layer "F.Cu")
		(net "M_D_CPU0_SA_DQ<21>")
	)
	(segment
		(start 258.130548 -290.177982)
		(end 257.626104 -290.177982)
		(width 0.20066)
		(layer "F.Cu")
		(net "M_D_CPU0_SA_DQ<21>")
	)
	(arc
		(start 347.003116 -270.475456)
		(mid 347.003052 -270.743426)
		(end 347.002862 -271.011396)
		(width 0.20066)
		(layer "F.Cu")
		(net "M_D_CPU0_SA_DQ<21>")
	)
	(segment
		(start 267.165582 -291.083492)
		(end 267.165582 -290.585398)
		(width 0.18288)
		(layer "In11.Cu")
		(net "M_D_CPU0_SA_DQ<21>")
	)
	(segment
		(start 345.316556 -270.69034)
		(end 345.304872 -270.683736)
		(width 0.088646)
		(layer "In11.Cu")
		(net "M_D_CPU0_SA_DQ<21>")
	)
	(segment
		(start 347.190314 -270.687038)
		(end 347.184472 -270.683736)
		(width 0.088646)
		(layer "In11.Cu")
		(net "M_D_CPU0_SA_DQ<21>")
	)
	(segment
		(start 331.004672 -273.255994)
		(end 327.556114 -273.255994)
		(width 0.18288)
		(layer "In11.Cu")
		(net "M_D_CPU0_SA_DQ<21>")
	)
	(segment
		(start 296.421556 -291.107368)
		(end 296.286428 -291.242496)
		(width 0.18288)
		(layer "In11.Cu")
		(net "M_D_CPU0_SA_DQ<21>")
	)
	(segment
		(start 314.858146 -285.953962)
		(end 312.156856 -285.953962)
		(width 0.18288)
		(layer "In11.Cu")
		(net "M_D_CPU0_SA_DQ<21>")
	)
	(segment
		(start 267.358622 -291.276532)
		(end 267.165582 -291.083492)
		(width 0.18288)
		(layer "In11.Cu")
		(net "M_D_CPU0_SA_DQ<21>")
	)
	(segment
		(start 307.945536 -287.94075)
		(end 307.28412 -287.94075)
		(width 0.18288)
		(layer "In11.Cu")
		(net "M_D_CPU0_SA_DQ<21>")
	)
	(segment
		(start 302.918114 -290.344606)
		(end 299.86224 -290.344606)
		(width 0.18288)
		(layer "In11.Cu")
		(net "M_D_CPU0_SA_DQ<21>")
	)
	(segment
		(start 296.286428 -291.242496)
		(end 293.953946 -291.242496)
		(width 0.18288)
		(layer "In11.Cu")
		(net "M_D_CPU0_SA_DQ<21>")
	)
	(segment
		(start 280.307542 -291.163756)
		(end 280.228802 -291.242496)
		(width 0.18288)
		(layer "In11.Cu")
		(net "M_D_CPU0_SA_DQ<21>")
	)
	(segment
		(start 292.295834 -292.026086)
		(end 292.171882 -292.150038)
		(width 0.18288)
		(layer "In11.Cu")
		(net "M_D_CPU0_SA_DQ<21>")
	)
	(segment
		(start 265.763502 -291.083492)
		(end 265.763502 -290.585398)
		(width 0.18288)
		(layer "In11.Cu")
		(net "M_D_CPU0_SA_DQ<21>")
	)
	(segment
		(start 267.866622 -291.083492)
		(end 267.673582 -291.276532)
		(width 0.18288)
		(layer "In11.Cu")
		(net "M_D_CPU0_SA_DQ<21>")
	)
	(segment
		(start 266.464542 -290.585398)
		(end 266.464542 -291.083492)
		(width 0.18288)
		(layer "In11.Cu")
		(net "M_D_CPU0_SA_DQ<21>")
	)
	(segment
		(start 312.156856 -285.953962)
		(end 309.668672 -286.984186)
		(width 0.18288)
		(layer "In11.Cu")
		(net "M_D_CPU0_SA_DQ<21>")
	)
	(segment
		(start 297.686984 -291.107368)
		(end 296.421556 -291.107368)
		(width 0.18288)
		(layer "In11.Cu")
		(net "M_D_CPU0_SA_DQ<21>")
	)
	(segment
		(start 289.454844 -291.165026)
		(end 288.508694 -291.165026)
		(width 0.18288)
		(layer "In11.Cu")
		(net "M_D_CPU0_SA_DQ<21>")
	)
	(segment
		(start 266.464542 -291.083492)
		(end 266.271502 -291.276532)
		(width 0.18288)
		(layer "In11.Cu")
		(net "M_D_CPU0_SA_DQ<21>")
	)
	(segment
		(start 280.228802 -291.242496)
		(end 279.342596 -291.242496)
		(width 0.18288)
		(layer "In11.Cu")
		(net "M_D_CPU0_SA_DQ<21>")
	)
	(segment
		(start 299.814488 -290.392358)
		(end 298.401994 -290.392358)
		(width 0.18288)
		(layer "In11.Cu")
		(net "M_D_CPU0_SA_DQ<21>")
	)
	(segment
		(start 331.834744 -272.07845)
		(end 331.621638 -272.291556)
		(width 0.088646)
		(layer "In11.Cu")
		(net "M_D_CPU0_SA_DQ<21>")
	)
	(segment
		(start 269.472156 -290.392358)
		(end 268.059662 -290.392358)
		(width 0.18288)
		(layer "In11.Cu")
		(net "M_D_CPU0_SA_DQ<21>")
	)
	(segment
		(start 303.888394 -289.374326)
		(end 302.918114 -290.344606)
		(width 0.18288)
		(layer "In11.Cu")
		(net "M_D_CPU0_SA_DQ<21>")
	)
	(segment
		(start 347.195394 -270.689832)
		(end 347.190314 -270.687038)
		(width 0.088646)
		(layer "In11.Cu")
		(net "M_D_CPU0_SA_DQ<21>")
	)
	(segment
		(start 269.578582 -290.285932)
		(end 269.472156 -290.392358)
		(width 0.18288)
		(layer "In11.Cu")
		(net "M_D_CPU0_SA_DQ<21>")
	)
	(segment
		(start 282.705302 -291.163756)
		(end 280.307542 -291.163756)
		(width 0.18288)
		(layer "In11.Cu")
		(net "M_D_CPU0_SA_DQ<21>")
	)
	(segment
		(start 331.834744 -271.627854)
		(end 331.834744 -272.07845)
		(width 0.088646)
		(layer "In11.Cu")
		(net "M_D_CPU0_SA_DQ<21>")
	)
	(segment
		(start 265.570462 -290.392358)
		(end 265.154918 -290.392358)
		(width 0.18288)
		(layer "In11.Cu")
		(net "M_D_CPU0_SA_DQ<21>")
	)
	(segment
		(start 287.647888 -290.30422)
		(end 284.690566 -290.30422)
		(width 0.18288)
		(layer "In11.Cu")
		(net "M_D_CPU0_SA_DQ<21>")
	)
	(segment
		(start 298.401994 -290.392358)
		(end 297.686984 -291.107368)
		(width 0.18288)
		(layer "In11.Cu")
		(net "M_D_CPU0_SA_DQ<21>")
	)
	(segment
		(start 344.376756 -270.69034)
		(end 344.365072 -270.683736)
		(width 0.088646)
		(layer "In11.Cu")
		(net "M_D_CPU0_SA_DQ<21>")
	)
	(segment
		(start 327.556114 -273.255994)
		(end 314.858146 -285.953962)
		(width 0.18288)
		(layer "In11.Cu")
		(net "M_D_CPU0_SA_DQ<21>")
	)
	(segment
		(start 265.763502 -290.585398)
		(end 265.570462 -290.392358)
		(width 0.18288)
		(layer "In11.Cu")
		(net "M_D_CPU0_SA_DQ<21>")
	)
	(segment
		(start 283.4767 -290.392358)
		(end 282.705302 -291.163756)
		(width 0.18288)
		(layer "In11.Cu")
		(net "M_D_CPU0_SA_DQ<21>")
	)
	(segment
		(start 331.621638 -273.04111)
		(end 331.406754 -273.255994)
		(width 0.088646)
		(layer "In11.Cu")
		(net "M_D_CPU0_SA_DQ<21>")
	)
	(segment
		(start 339.297264 -270.687038)
		(end 339.282532 -270.695674)
		(width 0.088646)
		(layer "In11.Cu")
		(net "M_D_CPU0_SA_DQ<21>")
	)
	(segment
		(start 290.039044 -291.749226)
		(end 289.454844 -291.165026)
		(width 0.18288)
		(layer "In11.Cu")
		(net "M_D_CPU0_SA_DQ<21>")
	)
	(segment
		(start 265.956542 -291.276532)
		(end 265.763502 -291.083492)
		(width 0.18288)
		(layer "In11.Cu")
		(net "M_D_CPU0_SA_DQ<21>")
	)
	(segment
		(start 284.690566 -290.30422)
		(end 284.602428 -290.392358)
		(width 0.18288)
		(layer "In11.Cu")
		(net "M_D_CPU0_SA_DQ<21>")
	)
	(segment
		(start 333.376016 -270.76273)
		(end 332.699868 -270.76273)
		(width 0.088646)
		(layer "In11.Cu")
		(net "M_D_CPU0_SA_DQ<21>")
	)
	(segment
		(start 343.996264 -270.687038)
		(end 343.981532 -270.695674)
		(width 0.088646)
		(layer "In11.Cu")
		(net "M_D_CPU0_SA_DQ<21>")
	)
	(segment
		(start 346.256356 -270.69034)
		(end 346.244672 -270.683736)
		(width 0.088646)
		(layer "In11.Cu")
		(net "M_D_CPU0_SA_DQ<21>")
	)
	(segment
		(start 308.9021 -286.984186)
		(end 307.945536 -287.94075)
		(width 0.18288)
		(layer "In11.Cu")
		(net "M_D_CPU0_SA_DQ<21>")
	)
	(segment
		(start 347.31579 -271.011396)
		(end 347.373194 -270.953992)
		(width 0.088646)
		(layer "In11.Cu")
		(net "M_D_CPU0_SA_DQ<21>")
	)
	(segment
		(start 277.344378 -291.999416)
		(end 276.484588 -291.139626)
		(width 0.18288)
		(layer "In11.Cu")
		(net "M_D_CPU0_SA_DQ<21>")
	)
	(segment
		(start 347.002862 -271.011396)
		(end 347.31579 -271.011396)
		(width 0.088646)
		(layer "In11.Cu")
		(net "M_D_CPU0_SA_DQ<21>")
	)
	(segment
		(start 307.079396 -287.736026)
		(end 306.339494 -287.736026)
		(width 0.18288)
		(layer "In11.Cu")
		(net "M_D_CPU0_SA_DQ<21>")
	)
	(segment
		(start 272.985738 -290.285932)
		(end 269.578582 -290.285932)
		(width 0.18288)
		(layer "In11.Cu")
		(net "M_D_CPU0_SA_DQ<21>")
	)
	(segment
		(start 309.668672 -286.984186)
		(end 308.9021 -286.984186)
		(width 0.18288)
		(layer "In11.Cu")
		(net "M_D_CPU0_SA_DQ<21>")
	)
	(segment
		(start 342.116918 -270.687038)
		(end 342.106504 -270.693134)
		(width 0.088646)
		(layer "In11.Cu")
		(net "M_D_CPU0_SA_DQ<21>")
	)
	(segment
		(start 331.406754 -273.255994)
		(end 331.004672 -273.255994)
		(width 0.088646)
		(layer "In11.Cu")
		(net "M_D_CPU0_SA_DQ<21>")
	)
	(segment
		(start 288.508694 -291.165026)
		(end 287.647888 -290.30422)
		(width 0.18288)
		(layer "In11.Cu")
		(net "M_D_CPU0_SA_DQ<21>")
	)
	(segment
		(start 290.883594 -291.749226)
		(end 290.039044 -291.749226)
		(width 0.18288)
		(layer "In11.Cu")
		(net "M_D_CPU0_SA_DQ<21>")
	)
	(segment
		(start 279.342596 -291.242496)
		(end 278.585676 -291.999416)
		(width 0.18288)
		(layer "In11.Cu")
		(net "M_D_CPU0_SA_DQ<21>")
	)
	(segment
		(start 341.176864 -270.687038)
		(end 341.162132 -270.695674)
		(width 0.088646)
		(layer "In11.Cu")
		(net "M_D_CPU0_SA_DQ<21>")
	)
	(segment
		(start 267.866622 -290.585398)
		(end 267.866622 -291.083492)
		(width 0.18288)
		(layer "In11.Cu")
		(net "M_D_CPU0_SA_DQ<21>")
	)
	(segment
		(start 332.699868 -270.76273)
		(end 331.834744 -271.627854)
		(width 0.088646)
		(layer "In11.Cu")
		(net "M_D_CPU0_SA_DQ<21>")
	)
	(segment
		(start 266.271502 -291.276532)
		(end 265.956542 -291.276532)
		(width 0.18288)
		(layer "In11.Cu")
		(net "M_D_CPU0_SA_DQ<21>")
	)
	(segment
		(start 284.602428 -290.392358)
		(end 283.4767 -290.392358)
		(width 0.18288)
		(layer "In11.Cu")
		(net "M_D_CPU0_SA_DQ<21>")
	)
	(segment
		(start 267.165582 -290.585398)
		(end 266.972542 -290.392358)
		(width 0.18288)
		(layer "In11.Cu")
		(net "M_D_CPU0_SA_DQ<21>")
	)
	(segment
		(start 299.86224 -290.344606)
		(end 299.814488 -290.392358)
		(width 0.18288)
		(layer "In11.Cu")
		(net "M_D_CPU0_SA_DQ<21>")
	)
	(segment
		(start 343.056464 -270.687038)
		(end 343.04605 -270.693134)
		(width 0.088646)
		(layer "In11.Cu")
		(net "M_D_CPU0_SA_DQ<21>")
	)
	(segment
		(start 331.621638 -272.291556)
		(end 331.621638 -273.04111)
		(width 0.088646)
		(layer "In11.Cu")
		(net "M_D_CPU0_SA_DQ<21>")
	)
	(segment
		(start 276.484588 -291.139626)
		(end 273.839432 -291.139626)
		(width 0.18288)
		(layer "In11.Cu")
		(net "M_D_CPU0_SA_DQ<21>")
	)
	(segment
		(start 266.657582 -290.392358)
		(end 266.464542 -290.585398)
		(width 0.18288)
		(layer "In11.Cu")
		(net "M_D_CPU0_SA_DQ<21>")
	)
	(segment
		(start 278.585676 -291.999416)
		(end 277.344378 -291.999416)
		(width 0.18288)
		(layer "In11.Cu")
		(net "M_D_CPU0_SA_DQ<21>")
	)
	(segment
		(start 291.284406 -292.150038)
		(end 290.883594 -291.749226)
		(width 0.18288)
		(layer "In11.Cu")
		(net "M_D_CPU0_SA_DQ<21>")
	)
	(segment
		(start 293.170356 -292.026086)
		(end 292.295834 -292.026086)
		(width 0.18288)
		(layer "In11.Cu")
		(net "M_D_CPU0_SA_DQ<21>")
	)
	(segment
		(start 292.171882 -292.150038)
		(end 291.284406 -292.150038)
		(width 0.18288)
		(layer "In11.Cu")
		(net "M_D_CPU0_SA_DQ<21>")
	)
	(segment
		(start 304.701194 -289.374326)
		(end 303.888394 -289.374326)
		(width 0.18288)
		(layer "In11.Cu")
		(net "M_D_CPU0_SA_DQ<21>")
	)
	(segment
		(start 293.953946 -291.242496)
		(end 293.170356 -292.026086)
		(width 0.18288)
		(layer "In11.Cu")
		(net "M_D_CPU0_SA_DQ<21>")
	)
	(segment
		(start 268.059662 -290.392358)
		(end 267.866622 -290.585398)
		(width 0.18288)
		(layer "In11.Cu")
		(net "M_D_CPU0_SA_DQ<21>")
	)
	(segment
		(start 267.673582 -291.276532)
		(end 267.358622 -291.276532)
		(width 0.18288)
		(layer "In11.Cu")
		(net "M_D_CPU0_SA_DQ<21>")
	)
	(segment
		(start 307.28412 -287.94075)
		(end 307.079396 -287.736026)
		(width 0.18288)
		(layer "In11.Cu")
		(net "M_D_CPU0_SA_DQ<21>")
	)
	(segment
		(start 306.339494 -287.736026)
		(end 304.701194 -289.374326)
		(width 0.18288)
		(layer "In11.Cu")
		(net "M_D_CPU0_SA_DQ<21>")
	)
	(segment
		(start 273.839432 -291.139626)
		(end 272.985738 -290.285932)
		(width 0.18288)
		(layer "In11.Cu")
		(net "M_D_CPU0_SA_DQ<21>")
	)
	(segment
		(start 266.972542 -290.392358)
		(end 266.657582 -290.392358)
		(width 0.18288)
		(layer "In11.Cu")
		(net "M_D_CPU0_SA_DQ<21>")
	)
	(segment
		(start 265.154918 -290.392358)
		(end 264.729214 -289.966654)
		(width 0.18288)
		(layer "In11.Cu")
		(net "M_D_CPU0_SA_DQ<21>")
	)
	(arc
		(start 346.815664 -270.687038)
		(mid 346.536461 -270.762678)
		(end 346.256356 -270.69034)
		(width 0.088646)
		(layer "In11.Cu")
		(net "M_D_CPU0_SA_DQ<21>")
	)
	(arc
		(start 335.538064 -270.687038)
		(mid 335.255362 -270.762814)
		(end 334.97266 -270.687038)
		(width 0.088646)
		(layer "In11.Cu")
		(net "M_D_CPU0_SA_DQ<21>")
	)
	(arc
		(start 338.73186 -270.687038)
		(mid 338.544662 -270.636895)
		(end 338.357464 -270.687038)
		(width 0.088646)
		(layer "In11.Cu")
		(net "M_D_CPU0_SA_DQ<21>")
	)
	(arc
		(start 340.61146 -270.687038)
		(mid 340.424262 -270.636895)
		(end 340.237064 -270.687038)
		(width 0.088646)
		(layer "In11.Cu")
		(net "M_D_CPU0_SA_DQ<21>")
	)
	(arc
		(start 333.658464 -270.687038)
		(mid 333.522221 -270.743484)
		(end 333.376016 -270.76273)
		(width 0.088646)
		(layer "In11.Cu")
		(net "M_D_CPU0_SA_DQ<21>")
	)
	(arc
		(start 336.477864 -270.687038)
		(mid 336.195162 -270.762814)
		(end 335.91246 -270.687038)
		(width 0.088646)
		(layer "In11.Cu")
		(net "M_D_CPU0_SA_DQ<21>")
	)
	(arc
		(start 338.357464 -270.687038)
		(mid 338.074762 -270.762814)
		(end 337.79206 -270.687038)
		(width 0.088646)
		(layer "In11.Cu")
		(net "M_D_CPU0_SA_DQ<21>")
	)
	(arc
		(start 344.936064 -270.687038)
		(mid 344.656861 -270.762678)
		(end 344.376756 -270.69034)
		(width 0.088646)
		(layer "In11.Cu")
		(net "M_D_CPU0_SA_DQ<21>")
	)
	(arc
		(start 340.237064 -270.687038)
		(mid 339.954362 -270.762814)
		(end 339.67166 -270.687038)
		(width 0.088646)
		(layer "In11.Cu")
		(net "M_D_CPU0_SA_DQ<21>")
	)
	(arc
		(start 339.67166 -270.687038)
		(mid 339.484462 -270.636895)
		(end 339.297264 -270.687038)
		(width 0.088646)
		(layer "In11.Cu")
		(net "M_D_CPU0_SA_DQ<21>")
	)
	(arc
		(start 343.43086 -270.687038)
		(mid 343.243662 -270.636895)
		(end 343.056464 -270.687038)
		(width 0.088646)
		(layer "In11.Cu")
		(net "M_D_CPU0_SA_DQ<21>")
	)
	(arc
		(start 339.282532 -270.695674)
		(mid 339.006057 -270.762994)
		(end 338.73186 -270.687038)
		(width 0.088646)
		(layer "In11.Cu")
		(net "M_D_CPU0_SA_DQ<21>")
	)
	(arc
		(start 347.184472 -270.683736)
		(mid 346.999617 -270.636786)
		(end 346.815664 -270.687038)
		(width 0.088646)
		(layer "In11.Cu")
		(net "M_D_CPU0_SA_DQ<21>")
	)
	(arc
		(start 337.79206 -270.687038)
		(mid 337.604862 -270.636895)
		(end 337.417664 -270.687038)
		(width 0.088646)
		(layer "In11.Cu")
		(net "M_D_CPU0_SA_DQ<21>")
	)
	(arc
		(start 347.373194 -270.953992)
		(mid 347.313729 -270.802105)
		(end 347.195394 -270.689832)
		(width 0.088646)
		(layer "In11.Cu")
		(net "M_D_CPU0_SA_DQ<21>")
	)
	(arc
		(start 345.875864 -270.687038)
		(mid 345.596661 -270.762678)
		(end 345.316556 -270.69034)
		(width 0.088646)
		(layer "In11.Cu")
		(net "M_D_CPU0_SA_DQ<21>")
	)
	(arc
		(start 341.162132 -270.695674)
		(mid 340.885657 -270.762994)
		(end 340.61146 -270.687038)
		(width 0.088646)
		(layer "In11.Cu")
		(net "M_D_CPU0_SA_DQ<21>")
	)
	(arc
		(start 343.981532 -270.695674)
		(mid 343.705057 -270.762994)
		(end 343.43086 -270.687038)
		(width 0.088646)
		(layer "In11.Cu")
		(net "M_D_CPU0_SA_DQ<21>")
	)
	(arc
		(start 343.04605 -270.693134)
		(mid 342.767872 -270.762857)
		(end 342.491314 -270.687038)
		(width 0.088646)
		(layer "In11.Cu")
		(net "M_D_CPU0_SA_DQ<21>")
	)
	(arc
		(start 334.03286 -270.687038)
		(mid 333.845662 -270.636895)
		(end 333.658464 -270.687038)
		(width 0.088646)
		(layer "In11.Cu")
		(net "M_D_CPU0_SA_DQ<21>")
	)
	(arc
		(start 335.91246 -270.687038)
		(mid 335.725262 -270.636895)
		(end 335.538064 -270.687038)
		(width 0.088646)
		(layer "In11.Cu")
		(net "M_D_CPU0_SA_DQ<21>")
	)
	(arc
		(start 342.491314 -270.687038)
		(mid 342.304116 -270.636895)
		(end 342.116918 -270.687038)
		(width 0.088646)
		(layer "In11.Cu")
		(net "M_D_CPU0_SA_DQ<21>")
	)
	(arc
		(start 342.106504 -270.693134)
		(mid 341.828072 -270.76298)
		(end 341.55126 -270.687038)
		(width 0.088646)
		(layer "In11.Cu")
		(net "M_D_CPU0_SA_DQ<21>")
	)
	(arc
		(start 345.304872 -270.683736)
		(mid 345.120017 -270.636786)
		(end 344.936064 -270.687038)
		(width 0.088646)
		(layer "In11.Cu")
		(net "M_D_CPU0_SA_DQ<21>")
	)
	(arc
		(start 336.85226 -270.687038)
		(mid 336.665062 -270.636895)
		(end 336.477864 -270.687038)
		(width 0.088646)
		(layer "In11.Cu")
		(net "M_D_CPU0_SA_DQ<21>")
	)
	(arc
		(start 344.365072 -270.683736)
		(mid 344.180217 -270.636786)
		(end 343.996264 -270.687038)
		(width 0.088646)
		(layer "In11.Cu")
		(net "M_D_CPU0_SA_DQ<21>")
	)
	(arc
		(start 337.417664 -270.687038)
		(mid 337.134962 -270.762814)
		(end 336.85226 -270.687038)
		(width 0.088646)
		(layer "In11.Cu")
		(net "M_D_CPU0_SA_DQ<21>")
	)
	(arc
		(start 341.55126 -270.687038)
		(mid 341.364062 -270.636895)
		(end 341.176864 -270.687038)
		(width 0.088646)
		(layer "In11.Cu")
		(net "M_D_CPU0_SA_DQ<21>")
	)
	(arc
		(start 334.97266 -270.687038)
		(mid 334.785462 -270.636895)
		(end 334.598264 -270.687038)
		(width 0.088646)
		(layer "In11.Cu")
		(net "M_D_CPU0_SA_DQ<21>")
	)
	(arc
		(start 334.598264 -270.687038)
		(mid 334.315562 -270.762814)
		(end 334.03286 -270.687038)
		(width 0.088646)
		(layer "In11.Cu")
		(net "M_D_CPU0_SA_DQ<21>")
	)
	(arc
		(start 346.244672 -270.683736)
		(mid 346.059817 -270.636786)
		(end 345.875864 -270.687038)
		(width 0.088646)
		(layer "In11.Cu")
		(net "M_D_CPU0_SA_DQ<21>")
	)
	(segment
		(start 258.28498 -291.443156)
		(end 258.28498 -291.732716)
		(width 0.20066)
		(layer "F.Cu")
		(net "M_D_CPU0_SA_DQ<20>")
	)
	(segment
		(start 263.624314 -291.666676)
		(end 262.255254 -291.666676)
		(width 0.20066)
		(layer "F.Cu")
		(net "M_D_CPU0_SA_DQ<20>")
	)
	(segment
		(start 264.729214 -291.666676)
		(end 263.624314 -291.666676)
		(width 0.20066)
		(layer "F.Cu")
		(net "M_D_CPU0_SA_DQ<20>")
	)
	(segment
		(start 258.49453 -291.233606)
		(end 258.28498 -291.443156)
		(width 0.20066)
		(layer "F.Cu")
		(net "M_D_CPU0_SA_DQ<20>")
	)
	(segment
		(start 346.533216 -271.289526)
		(end 346.533216 -271.825212)
		(width 0.20066)
		(layer "F.Cu")
		(net "M_D_CPU0_SA_DQ<20>")
	)
	(segment
		(start 262.255254 -291.666676)
		(end 261.830312 -291.241734)
		(width 0.20066)
		(layer "F.Cu")
		(net "M_D_CPU0_SA_DQ<20>")
	)
	(segment
		(start 257.653536 -291.905436)
		(end 257.414776 -291.666676)
		(width 0.20066)
		(layer "F.Cu")
		(net "M_D_CPU0_SA_DQ<20>")
	)
	(segment
		(start 261.381494 -291.241734)
		(end 259.31241 -291.241734)
		(width 0.1016)
		(layer "F.Cu")
		(net "M_D_CPU0_SA_DQ<20>")
	)
	(segment
		(start 257.414776 -291.666676)
		(end 256.080514 -291.666676)
		(width 0.20066)
		(layer "F.Cu")
		(net "M_D_CPU0_SA_DQ<20>")
	)
	(segment
		(start 261.830312 -291.241734)
		(end 261.381494 -291.241734)
		(width 0.20066)
		(layer "F.Cu")
		(net "M_D_CPU0_SA_DQ<20>")
	)
	(segment
		(start 259.056378 -291.233606)
		(end 258.49453 -291.233606)
		(width 0.20066)
		(layer "F.Cu")
		(net "M_D_CPU0_SA_DQ<20>")
	)
	(segment
		(start 258.11226 -291.905436)
		(end 257.653536 -291.905436)
		(width 0.20066)
		(layer "F.Cu")
		(net "M_D_CPU0_SA_DQ<20>")
	)
	(segment
		(start 259.064506 -291.241734)
		(end 259.056378 -291.233606)
		(width 0.101854)
		(layer "F.Cu")
		(net "M_D_CPU0_SA_DQ<20>")
	)
	(segment
		(start 258.28498 -291.732716)
		(end 258.11226 -291.905436)
		(width 0.20066)
		(layer "F.Cu")
		(net "M_D_CPU0_SA_DQ<20>")
	)
	(segment
		(start 346.532962 -271.289272)
		(end 346.533216 -271.289526)
		(width 0.20066)
		(layer "F.Cu")
		(net "M_D_CPU0_SA_DQ<20>")
	)
	(segment
		(start 259.31241 -291.241734)
		(end 259.064506 -291.241734)
		(width 0.101854)
		(layer "F.Cu")
		(net "M_D_CPU0_SA_DQ<20>")
	)
	(segment
		(start 295.731438 -292.942518)
		(end 294.301164 -292.942518)
		(width 0.18288)
		(layer "In11.Cu")
		(net "M_D_CPU0_SA_DQ<20>")
	)
	(segment
		(start 268.102334 -292.09238)
		(end 267.858494 -292.33622)
		(width 0.18288)
		(layer "In11.Cu")
		(net "M_D_CPU0_SA_DQ<20>")
	)
	(segment
		(start 307.157882 -289.545014)
		(end 307.101494 -289.488626)
		(width 0.18288)
		(layer "In11.Cu")
		(net "M_D_CPU0_SA_DQ<20>")
	)
	(segment
		(start 297.458892 -292.942518)
		(end 296.818558 -292.942518)
		(width 0.18288)
		(layer "In11.Cu")
		(net "M_D_CPU0_SA_DQ<20>")
	)
	(segment
		(start 296.117518 -293.772082)
		(end 295.924478 -293.579042)
		(width 0.18288)
		(layer "In11.Cu")
		(net "M_D_CPU0_SA_DQ<20>")
	)
	(segment
		(start 306.239926 -289.488626)
		(end 304.614326 -291.114226)
		(width 0.18288)
		(layer "In11.Cu")
		(net "M_D_CPU0_SA_DQ<20>")
	)
	(segment
		(start 265.398758 -292.33622)
		(end 264.729214 -291.666676)
		(width 0.18288)
		(layer "In11.Cu")
		(net "M_D_CPU0_SA_DQ<20>")
	)
	(segment
		(start 273.515582 -292.474904)
		(end 272.945098 -291.90442)
		(width 0.18288)
		(layer "In11.Cu")
		(net "M_D_CPU0_SA_DQ<20>")
	)
	(segment
		(start 312.854594 -288.394648)
		(end 312.661554 -288.201608)
		(width 0.18288)
		(layer "In11.Cu")
		(net "M_D_CPU0_SA_DQ<20>")
	)
	(segment
		(start 269.661894 -291.90442)
		(end 269.473934 -292.09238)
		(width 0.18288)
		(layer "In11.Cu")
		(net "M_D_CPU0_SA_DQ<20>")
	)
	(segment
		(start 287.593024 -291.997384)
		(end 284.781498 -291.997384)
		(width 0.18288)
		(layer "In11.Cu")
		(net "M_D_CPU0_SA_DQ<20>")
	)
	(segment
		(start 312.468514 -287.654492)
		(end 311.63387 -287.654492)
		(width 0.18288)
		(layer "In11.Cu")
		(net "M_D_CPU0_SA_DQ<20>")
	)
	(segment
		(start 332.735936 -271.583658)
		(end 332.5495 -271.583658)
		(width 0.088646)
		(layer "In11.Cu")
		(net "M_D_CPU0_SA_DQ<20>")
	)
	(segment
		(start 299.845984 -292.001194)
		(end 299.754798 -292.09238)
		(width 0.18288)
		(layer "In11.Cu")
		(net "M_D_CPU0_SA_DQ<20>")
	)
	(segment
		(start 345.411806 -271.497552)
		(end 345.405964 -271.500854)
		(width 0.088646)
		(layer "In11.Cu")
		(net "M_D_CPU0_SA_DQ<20>")
	)
	(segment
		(start 340.156546 -271.50949)
		(end 340.141814 -271.500854)
		(width 0.088646)
		(layer "In11.Cu")
		(net "M_D_CPU0_SA_DQ<20>")
	)
	(segment
		(start 311.63387 -287.654492)
		(end 311.189878 -288.098484)
		(width 0.18288)
		(layer "In11.Cu")
		(net "M_D_CPU0_SA_DQ<20>")
	)
	(segment
		(start 296.432478 -293.772082)
		(end 296.117518 -293.772082)
		(width 0.18288)
		(layer "In11.Cu")
		(net "M_D_CPU0_SA_DQ<20>")
	)
	(segment
		(start 294.301164 -292.942518)
		(end 293.716456 -293.527226)
		(width 0.18288)
		(layer "In11.Cu")
		(net "M_D_CPU0_SA_DQ<20>")
	)
	(segment
		(start 328.026522 -274.271994)
		(end 314.644024 -287.654492)
		(width 0.18288)
		(layer "In11.Cu")
		(net "M_D_CPU0_SA_DQ<20>")
	)
	(segment
		(start 346.17787 -271.729962)
		(end 345.780614 -271.500854)
		(width 0.088646)
		(layer "In11.Cu")
		(net "M_D_CPU0_SA_DQ<20>")
	)
	(segment
		(start 310.299862 -289.545014)
		(end 307.157882 -289.545014)
		(width 0.18288)
		(layer "In11.Cu")
		(net "M_D_CPU0_SA_DQ<20>")
	)
	(segment
		(start 295.924478 -293.135558)
		(end 295.731438 -292.942518)
		(width 0.18288)
		(layer "In11.Cu")
		(net "M_D_CPU0_SA_DQ<20>")
	)
	(segment
		(start 291.01669 -293.527226)
		(end 290.35629 -292.866826)
		(width 0.18288)
		(layer "In11.Cu")
		(net "M_D_CPU0_SA_DQ<20>")
	)
	(segment
		(start 332.905862 -271.576546)
		(end 332.743048 -271.576546)
		(width 0.088646)
		(layer "In11.Cu")
		(net "M_D_CPU0_SA_DQ<20>")
	)
	(segment
		(start 313.172094 -288.394648)
		(end 312.854594 -288.394648)
		(width 0.18288)
		(layer "In11.Cu")
		(net "M_D_CPU0_SA_DQ<20>")
	)
	(segment
		(start 267.858494 -292.33622)
		(end 265.398758 -292.33622)
		(width 0.18288)
		(layer "In11.Cu")
		(net "M_D_CPU0_SA_DQ<20>")
	)
	(segment
		(start 299.754798 -292.09238)
		(end 298.30903 -292.09238)
		(width 0.18288)
		(layer "In11.Cu")
		(net "M_D_CPU0_SA_DQ<20>")
	)
	(segment
		(start 341.096346 -271.50949)
		(end 341.081614 -271.500854)
		(width 0.088646)
		(layer "In11.Cu")
		(net "M_D_CPU0_SA_DQ<20>")
	)
	(segment
		(start 312.661554 -287.847532)
		(end 312.468514 -287.654492)
		(width 0.18288)
		(layer "In11.Cu")
		(net "M_D_CPU0_SA_DQ<20>")
	)
	(segment
		(start 346.533216 -271.825212)
		(end 346.532962 -271.824958)
		(width 0.088646)
		(layer "In11.Cu")
		(net "M_D_CPU0_SA_DQ<20>")
	)
	(segment
		(start 284.781498 -291.997384)
		(end 284.686502 -292.09238)
		(width 0.18288)
		(layer "In11.Cu")
		(net "M_D_CPU0_SA_DQ<20>")
	)
	(segment
		(start 274.150582 -292.737794)
		(end 273.515582 -292.474904)
		(width 0.18288)
		(layer "In11.Cu")
		(net "M_D_CPU0_SA_DQ<20>")
	)
	(segment
		(start 313.365134 -287.847532)
		(end 313.365134 -288.201608)
		(width 0.18288)
		(layer "In11.Cu")
		(net "M_D_CPU0_SA_DQ<20>")
	)
	(segment
		(start 293.716456 -293.527226)
		(end 291.01669 -293.527226)
		(width 0.18288)
		(layer "In11.Cu")
		(net "M_D_CPU0_SA_DQ<20>")
	)
	(segment
		(start 272.945098 -291.90442)
		(end 269.661894 -291.90442)
		(width 0.18288)
		(layer "In11.Cu")
		(net "M_D_CPU0_SA_DQ<20>")
	)
	(segment
		(start 337.332828 -271.50695)
		(end 337.322414 -271.500854)
		(width 0.088646)
		(layer "In11.Cu")
		(net "M_D_CPU0_SA_DQ<20>")
	)
	(segment
		(start 304.614326 -291.114226)
		(end 303.872138 -291.114226)
		(width 0.18288)
		(layer "In11.Cu")
		(net "M_D_CPU0_SA_DQ<20>")
	)
	(segment
		(start 331.004926 -274.271994)
		(end 328.026522 -274.271994)
		(width 0.18288)
		(layer "In11.Cu")
		(net "M_D_CPU0_SA_DQ<20>")
	)
	(segment
		(start 345.405964 -271.500854)
		(end 345.400122 -271.50441)
		(width 0.088646)
		(layer "In11.Cu")
		(net "M_D_CPU0_SA_DQ<20>")
	)
	(segment
		(start 311.189878 -288.654998)
		(end 310.299862 -289.545014)
		(width 0.18288)
		(layer "In11.Cu")
		(net "M_D_CPU0_SA_DQ<20>")
	)
	(segment
		(start 288.462466 -292.866826)
		(end 287.593024 -291.997384)
		(width 0.18288)
		(layer "In11.Cu")
		(net "M_D_CPU0_SA_DQ<20>")
	)
	(segment
		(start 339.212174 -271.50695)
		(end 339.20176 -271.500854)
		(width 0.088646)
		(layer "In11.Cu")
		(net "M_D_CPU0_SA_DQ<20>")
	)
	(segment
		(start 282.626562 -292.942518)
		(end 279.29205 -292.942518)
		(width 0.18288)
		(layer "In11.Cu")
		(net "M_D_CPU0_SA_DQ<20>")
	)
	(segment
		(start 275.908262 -292.737794)
		(end 274.150582 -292.737794)
		(width 0.18288)
		(layer "In11.Cu")
		(net "M_D_CPU0_SA_DQ<20>")
	)
	(segment
		(start 314.644024 -287.654492)
		(end 313.558174 -287.654492)
		(width 0.18288)
		(layer "In11.Cu")
		(net "M_D_CPU0_SA_DQ<20>")
	)
	(segment
		(start 290.35629 -292.866826)
		(end 288.462466 -292.866826)
		(width 0.18288)
		(layer "In11.Cu")
		(net "M_D_CPU0_SA_DQ<20>")
	)
	(segment
		(start 332.215236 -272.263108)
		(end 332.01991 -272.458434)
		(width 0.088646)
		(layer "In11.Cu")
		(net "M_D_CPU0_SA_DQ<20>")
	)
	(segment
		(start 336.392774 -271.50695)
		(end 336.38236 -271.500854)
		(width 0.088646)
		(layer "In11.Cu")
		(net "M_D_CPU0_SA_DQ<20>")
	)
	(segment
		(start 342.975946 -271.50949)
		(end 342.961214 -271.500854)
		(width 0.088646)
		(layer "In11.Cu")
		(net "M_D_CPU0_SA_DQ<20>")
	)
	(segment
		(start 296.625518 -293.579042)
		(end 296.432478 -293.772082)
		(width 0.18288)
		(layer "In11.Cu")
		(net "M_D_CPU0_SA_DQ<20>")
	)
	(segment
		(start 311.189878 -288.098484)
		(end 311.189878 -288.654998)
		(width 0.18288)
		(layer "In11.Cu")
		(net "M_D_CPU0_SA_DQ<20>")
	)
	(segment
		(start 278.442166 -293.792402)
		(end 276.96287 -293.792402)
		(width 0.18288)
		(layer "In11.Cu")
		(net "M_D_CPU0_SA_DQ<20>")
	)
	(segment
		(start 332.5495 -271.583658)
		(end 332.215236 -271.917922)
		(width 0.088646)
		(layer "In11.Cu")
		(net "M_D_CPU0_SA_DQ<20>")
	)
	(segment
		(start 343.915746 -271.50949)
		(end 343.901014 -271.500854)
		(width 0.088646)
		(layer "In11.Cu")
		(net "M_D_CPU0_SA_DQ<20>")
	)
	(segment
		(start 313.558174 -287.654492)
		(end 313.365134 -287.847532)
		(width 0.18288)
		(layer "In11.Cu")
		(net "M_D_CPU0_SA_DQ<20>")
	)
	(segment
		(start 331.155294 -274.271994)
		(end 331.004926 -274.271994)
		(width 0.088646)
		(layer "In11.Cu")
		(net "M_D_CPU0_SA_DQ<20>")
	)
	(segment
		(start 303.872138 -291.114226)
		(end 302.98517 -292.001194)
		(width 0.18288)
		(layer "In11.Cu")
		(net "M_D_CPU0_SA_DQ<20>")
	)
	(segment
		(start 332.01991 -273.407378)
		(end 331.155294 -274.271994)
		(width 0.088646)
		(layer "In11.Cu")
		(net "M_D_CPU0_SA_DQ<20>")
	)
	(segment
		(start 279.29205 -292.942518)
		(end 278.442166 -293.792402)
		(width 0.18288)
		(layer "In11.Cu")
		(net "M_D_CPU0_SA_DQ<20>")
	)
	(segment
		(start 302.98517 -292.001194)
		(end 299.845984 -292.001194)
		(width 0.18288)
		(layer "In11.Cu")
		(net "M_D_CPU0_SA_DQ<20>")
	)
	(segment
		(start 276.96287 -293.792402)
		(end 275.908262 -292.737794)
		(width 0.18288)
		(layer "In11.Cu")
		(net "M_D_CPU0_SA_DQ<20>")
	)
	(segment
		(start 332.01991 -272.458434)
		(end 332.01991 -273.407378)
		(width 0.088646)
		(layer "In11.Cu")
		(net "M_D_CPU0_SA_DQ<20>")
	)
	(segment
		(start 269.473934 -292.09238)
		(end 268.102334 -292.09238)
		(width 0.18288)
		(layer "In11.Cu")
		(net "M_D_CPU0_SA_DQ<20>")
	)
	(segment
		(start 332.743048 -271.576546)
		(end 332.735936 -271.583658)
		(width 0.088646)
		(layer "In11.Cu")
		(net "M_D_CPU0_SA_DQ<20>")
	)
	(segment
		(start 298.30903 -292.09238)
		(end 297.458892 -292.942518)
		(width 0.18288)
		(layer "In11.Cu")
		(net "M_D_CPU0_SA_DQ<20>")
	)
	(segment
		(start 283.4767 -292.09238)
		(end 282.626562 -292.942518)
		(width 0.18288)
		(layer "In11.Cu")
		(net "M_D_CPU0_SA_DQ<20>")
	)
	(segment
		(start 307.101494 -289.488626)
		(end 306.239926 -289.488626)
		(width 0.18288)
		(layer "In11.Cu")
		(net "M_D_CPU0_SA_DQ<20>")
	)
	(segment
		(start 332.215236 -271.917922)
		(end 332.215236 -272.263108)
		(width 0.088646)
		(layer "In11.Cu")
		(net "M_D_CPU0_SA_DQ<20>")
	)
	(segment
		(start 312.661554 -288.201608)
		(end 312.661554 -287.847532)
		(width 0.18288)
		(layer "In11.Cu")
		(net "M_D_CPU0_SA_DQ<20>")
	)
	(segment
		(start 296.818558 -292.942518)
		(end 296.625518 -293.135558)
		(width 0.18288)
		(layer "In11.Cu")
		(net "M_D_CPU0_SA_DQ<20>")
	)
	(segment
		(start 295.924478 -293.579042)
		(end 295.924478 -293.135558)
		(width 0.18288)
		(layer "In11.Cu")
		(net "M_D_CPU0_SA_DQ<20>")
	)
	(segment
		(start 313.365134 -288.201608)
		(end 313.172094 -288.394648)
		(width 0.18288)
		(layer "In11.Cu")
		(net "M_D_CPU0_SA_DQ<20>")
	)
	(segment
		(start 284.686502 -292.09238)
		(end 283.4767 -292.09238)
		(width 0.18288)
		(layer "In11.Cu")
		(net "M_D_CPU0_SA_DQ<20>")
	)
	(segment
		(start 296.625518 -293.135558)
		(end 296.625518 -293.579042)
		(width 0.18288)
		(layer "In11.Cu")
		(net "M_D_CPU0_SA_DQ<20>")
	)
	(arc
		(start 341.081614 -271.500854)
		(mid 340.894416 -271.450711)
		(end 340.707218 -271.500854)
		(width 0.088646)
		(layer "In11.Cu")
		(net "M_D_CPU0_SA_DQ<20>")
	)
	(arc
		(start 346.532962 -271.824958)
		(mid 346.349155 -271.800846)
		(end 346.17787 -271.729962)
		(width 0.088646)
		(layer "In11.Cu")
		(net "M_D_CPU0_SA_DQ<20>")
	)
	(arc
		(start 343.526618 -271.500854)
		(mid 343.252419 -271.576689)
		(end 342.975946 -271.50949)
		(width 0.088646)
		(layer "In11.Cu")
		(net "M_D_CPU0_SA_DQ<20>")
	)
	(arc
		(start 334.50276 -271.500854)
		(mid 334.315562 -271.450711)
		(end 334.128364 -271.500854)
		(width 0.088646)
		(layer "In11.Cu")
		(net "M_D_CPU0_SA_DQ<20>")
	)
	(arc
		(start 335.068164 -271.500854)
		(mid 334.785462 -271.57663)
		(end 334.50276 -271.500854)
		(width 0.088646)
		(layer "In11.Cu")
		(net "M_D_CPU0_SA_DQ<20>")
	)
	(arc
		(start 340.141814 -271.500854)
		(mid 339.954616 -271.450711)
		(end 339.767418 -271.500854)
		(width 0.088646)
		(layer "In11.Cu")
		(net "M_D_CPU0_SA_DQ<20>")
	)
	(arc
		(start 343.901014 -271.500854)
		(mid 343.713816 -271.450711)
		(end 343.526618 -271.500854)
		(width 0.088646)
		(layer "In11.Cu")
		(net "M_D_CPU0_SA_DQ<20>")
	)
	(arc
		(start 341.647018 -271.500854)
		(mid 341.372819 -271.576689)
		(end 341.096346 -271.50949)
		(width 0.088646)
		(layer "In11.Cu")
		(net "M_D_CPU0_SA_DQ<20>")
	)
	(arc
		(start 337.322414 -271.500854)
		(mid 337.135216 -271.450711)
		(end 336.948018 -271.500854)
		(width 0.088646)
		(layer "In11.Cu")
		(net "M_D_CPU0_SA_DQ<20>")
	)
	(arc
		(start 334.128364 -271.500854)
		(mid 333.845662 -271.57663)
		(end 333.56296 -271.500854)
		(width 0.088646)
		(layer "In11.Cu")
		(net "M_D_CPU0_SA_DQ<20>")
	)
	(arc
		(start 344.466418 -271.500854)
		(mid 344.192219 -271.576689)
		(end 343.915746 -271.50949)
		(width 0.088646)
		(layer "In11.Cu")
		(net "M_D_CPU0_SA_DQ<20>")
	)
	(arc
		(start 342.586818 -271.500854)
		(mid 342.304116 -271.57663)
		(end 342.021414 -271.500854)
		(width 0.088646)
		(layer "In11.Cu")
		(net "M_D_CPU0_SA_DQ<20>")
	)
	(arc
		(start 337.887564 -271.500854)
		(mid 337.611005 -271.576597)
		(end 337.332828 -271.50695)
		(width 0.088646)
		(layer "In11.Cu")
		(net "M_D_CPU0_SA_DQ<20>")
	)
	(arc
		(start 336.38236 -271.500854)
		(mid 336.195162 -271.450711)
		(end 336.007964 -271.500854)
		(width 0.088646)
		(layer "In11.Cu")
		(net "M_D_CPU0_SA_DQ<20>")
	)
	(arc
		(start 333.56296 -271.500854)
		(mid 333.375762 -271.450711)
		(end 333.188564 -271.500854)
		(width 0.088646)
		(layer "In11.Cu")
		(net "M_D_CPU0_SA_DQ<20>")
	)
	(arc
		(start 335.44256 -271.500854)
		(mid 335.255362 -271.450711)
		(end 335.068164 -271.500854)
		(width 0.088646)
		(layer "In11.Cu")
		(net "M_D_CPU0_SA_DQ<20>")
	)
	(arc
		(start 345.780614 -271.500854)
		(mid 345.59666 -271.450725)
		(end 345.411806 -271.497552)
		(width 0.088646)
		(layer "In11.Cu")
		(net "M_D_CPU0_SA_DQ<20>")
	)
	(arc
		(start 338.26196 -271.500854)
		(mid 338.074762 -271.450711)
		(end 337.887564 -271.500854)
		(width 0.088646)
		(layer "In11.Cu")
		(net "M_D_CPU0_SA_DQ<20>")
	)
	(arc
		(start 342.961214 -271.500854)
		(mid 342.774016 -271.450711)
		(end 342.586818 -271.500854)
		(width 0.088646)
		(layer "In11.Cu")
		(net "M_D_CPU0_SA_DQ<20>")
	)
	(arc
		(start 342.021414 -271.500854)
		(mid 341.834216 -271.450711)
		(end 341.647018 -271.500854)
		(width 0.088646)
		(layer "In11.Cu")
		(net "M_D_CPU0_SA_DQ<20>")
	)
	(arc
		(start 339.767418 -271.500854)
		(mid 339.490605 -271.576724)
		(end 339.212174 -271.50695)
		(width 0.088646)
		(layer "In11.Cu")
		(net "M_D_CPU0_SA_DQ<20>")
	)
	(arc
		(start 333.188564 -271.500854)
		(mid 333.052195 -271.557296)
		(end 332.905862 -271.576546)
		(width 0.088646)
		(layer "In11.Cu")
		(net "M_D_CPU0_SA_DQ<20>")
	)
	(arc
		(start 336.948018 -271.500854)
		(mid 336.671205 -271.576724)
		(end 336.392774 -271.50695)
		(width 0.088646)
		(layer "In11.Cu")
		(net "M_D_CPU0_SA_DQ<20>")
	)
	(arc
		(start 344.840814 -271.500854)
		(mid 344.653616 -271.450711)
		(end 344.466418 -271.500854)
		(width 0.088646)
		(layer "In11.Cu")
		(net "M_D_CPU0_SA_DQ<20>")
	)
	(arc
		(start 345.400122 -271.50441)
		(mid 345.119987 -271.576693)
		(end 344.840814 -271.500854)
		(width 0.088646)
		(layer "In11.Cu")
		(net "M_D_CPU0_SA_DQ<20>")
	)
	(arc
		(start 336.007964 -271.500854)
		(mid 335.725262 -271.57663)
		(end 335.44256 -271.500854)
		(width 0.088646)
		(layer "In11.Cu")
		(net "M_D_CPU0_SA_DQ<20>")
	)
	(arc
		(start 339.20176 -271.500854)
		(mid 339.014562 -271.450711)
		(end 338.827364 -271.500854)
		(width 0.088646)
		(layer "In11.Cu")
		(net "M_D_CPU0_SA_DQ<20>")
	)
	(arc
		(start 338.827364 -271.500854)
		(mid 338.544662 -271.57663)
		(end 338.26196 -271.500854)
		(width 0.088646)
		(layer "In11.Cu")
		(net "M_D_CPU0_SA_DQ<20>")
	)
	(arc
		(start 340.707218 -271.500854)
		(mid 340.433019 -271.576689)
		(end 340.156546 -271.50949)
		(width 0.088646)
		(layer "In11.Cu")
		(net "M_D_CPU0_SA_DQ<20>")
	)
	(segment
		(start 259.065268 -314.19165)
		(end 259.056378 -314.18276)
		(width 0.1016)
		(layer "F.Cu")
		(net "M_D_CPU0_SA_DQ<1>")
	)
	(segment
		(start 258.28498 -314.673488)
		(end 258.130548 -314.82792)
		(width 0.20066)
		(layer "F.Cu")
		(net "M_D_CPU0_SA_DQ<1>")
	)
	(segment
		(start 261.050786 -314.19165)
		(end 259.065268 -314.19165)
		(width 0.1016)
		(layer "F.Cu")
		(net "M_D_CPU0_SA_DQ<1>")
	)
	(segment
		(start 258.130548 -314.82792)
		(end 257.626104 -314.82792)
		(width 0.20066)
		(layer "F.Cu")
		(net "M_D_CPU0_SA_DQ<1>")
	)
	(segment
		(start 259.056378 -314.18276)
		(end 258.44754 -314.18276)
		(width 0.20066)
		(layer "F.Cu")
		(net "M_D_CPU0_SA_DQ<1>")
	)
	(segment
		(start 258.28498 -314.34532)
		(end 258.28498 -314.673488)
		(width 0.20066)
		(layer "F.Cu")
		(net "M_D_CPU0_SA_DQ<1>")
	)
	(segment
		(start 261.381494 -314.19165)
		(end 261.050786 -314.19165)
		(width 0.101854)
		(layer "F.Cu")
		(net "M_D_CPU0_SA_DQ<1>")
	)
	(segment
		(start 261.560056 -314.19165)
		(end 261.381494 -314.19165)
		(width 0.20066)
		(layer "F.Cu")
		(net "M_D_CPU0_SA_DQ<1>")
	)
	(segment
		(start 263.624314 -314.616592)
		(end 261.984998 -314.616592)
		(width 0.20066)
		(layer "F.Cu")
		(net "M_D_CPU0_SA_DQ<1>")
	)
	(segment
		(start 258.44754 -314.18276)
		(end 258.28498 -314.34532)
		(width 0.20066)
		(layer "F.Cu")
		(net "M_D_CPU0_SA_DQ<1>")
	)
	(segment
		(start 257.626104 -314.82792)
		(end 257.414776 -314.616592)
		(width 0.20066)
		(layer "F.Cu")
		(net "M_D_CPU0_SA_DQ<1>")
	)
	(segment
		(start 257.414776 -314.616592)
		(end 256.080514 -314.616592)
		(width 0.20066)
		(layer "F.Cu")
		(net "M_D_CPU0_SA_DQ<1>")
	)
	(segment
		(start 264.729214 -314.616592)
		(end 263.624314 -314.616592)
		(width 0.20066)
		(layer "F.Cu")
		(net "M_D_CPU0_SA_DQ<1>")
	)
	(segment
		(start 261.984998 -314.616592)
		(end 261.560056 -314.19165)
		(width 0.20066)
		(layer "F.Cu")
		(net "M_D_CPU0_SA_DQ<1>")
	)
	(arc
		(start 343.243916 -275.35886)
		(mid 343.243852 -275.62683)
		(end 343.243662 -275.8948)
		(width 0.20066)
		(layer "F.Cu")
		(net "M_D_CPU0_SA_DQ<1>")
	)
	(segment
		(start 312.600848 -302.54448)
		(end 310.96839 -302.54448)
		(width 0.18288)
		(layer "In6.Cu")
		(net "M_D_CPU0_SA_DQ<1>")
	)
	(segment
		(start 285.360364 -316.741556)
		(end 282.84043 -316.741556)
		(width 0.18288)
		(layer "In6.Cu")
		(net "M_D_CPU0_SA_DQ<1>")
	)
	(segment
		(start 337.887564 -278.012144)
		(end 337.878674 -278.017224)
		(width 0.088646)
		(layer "In6.Cu")
		(net "M_D_CPU0_SA_DQ<1>")
	)
	(segment
		(start 281.990546 -315.891672)
		(end 279.116536 -315.891672)
		(width 0.18288)
		(layer "In6.Cu")
		(net "M_D_CPU0_SA_DQ<1>")
	)
	(segment
		(start 293.901876 -311.641744)
		(end 293.099744 -312.443876)
		(width 0.18288)
		(layer "In6.Cu")
		(net "M_D_CPU0_SA_DQ<1>")
	)
	(segment
		(start 334.598264 -278.82596)
		(end 334.589374 -278.83104)
		(width 0.088646)
		(layer "In6.Cu")
		(net "M_D_CPU0_SA_DQ<1>")
	)
	(segment
		(start 279.116536 -315.891672)
		(end 278.143716 -314.918852)
		(width 0.18288)
		(layer "In6.Cu")
		(net "M_D_CPU0_SA_DQ<1>")
	)
	(segment
		(start 291.647372 -313.449716)
		(end 290.48456 -313.449716)
		(width 0.18288)
		(layer "In6.Cu")
		(net "M_D_CPU0_SA_DQ<1>")
	)
	(segment
		(start 341.096346 -276.392894)
		(end 341.081614 -276.384258)
		(width 0.088646)
		(layer "In6.Cu")
		(net "M_D_CPU0_SA_DQ<1>")
	)
	(segment
		(start 332.054708 -281.976576)
		(end 317.135764 -296.89552)
		(width 0.18288)
		(layer "In6.Cu")
		(net "M_D_CPU0_SA_DQ<1>")
	)
	(segment
		(start 334.128364 -279.639776)
		(end 334.119474 -279.644856)
		(width 0.088646)
		(layer "In6.Cu")
		(net "M_D_CPU0_SA_DQ<1>")
	)
	(segment
		(start 334.410812 -279.150318)
		(end 334.410812 -279.160224)
		(width 0.088646)
		(layer "In6.Cu")
		(net "M_D_CPU0_SA_DQ<1>")
	)
	(segment
		(start 333.940912 -279.964134)
		(end 333.940912 -279.982676)
		(width 0.088646)
		(layer "In6.Cu")
		(net "M_D_CPU0_SA_DQ<1>")
	)
	(segment
		(start 288.7472 -314.049664)
		(end 287.903412 -314.893452)
		(width 0.18288)
		(layer "In6.Cu")
		(net "M_D_CPU0_SA_DQ<1>")
	)
	(segment
		(start 266.873228 -315.66358)
		(end 265.776202 -315.66358)
		(width 0.18288)
		(layer "In6.Cu")
		(net "M_D_CPU0_SA_DQ<1>")
	)
	(segment
		(start 333.362046 -280.731468)
		(end 333.362046 -281.373326)
		(width 0.088646)
		(layer "In6.Cu")
		(net "M_D_CPU0_SA_DQ<1>")
	)
	(segment
		(start 276.532086 -314.12434)
		(end 273.727418 -314.12434)
		(width 0.18288)
		(layer "In6.Cu")
		(net "M_D_CPU0_SA_DQ<1>")
	)
	(segment
		(start 317.135764 -296.89552)
		(end 317.135764 -298.922186)
		(width 0.18288)
		(layer "In6.Cu")
		(net "M_D_CPU0_SA_DQ<1>")
	)
	(segment
		(start 272.80997 -315.041788)
		(end 267.49502 -315.041788)
		(width 0.18288)
		(layer "In6.Cu")
		(net "M_D_CPU0_SA_DQ<1>")
	)
	(segment
		(start 277.326598 -314.918852)
		(end 276.532086 -314.12434)
		(width 0.18288)
		(layer "In6.Cu")
		(net "M_D_CPU0_SA_DQ<1>")
	)
	(segment
		(start 333.362046 -281.373326)
		(end 332.758796 -281.976576)
		(width 0.088646)
		(layer "In6.Cu")
		(net "M_D_CPU0_SA_DQ<1>")
	)
	(segment
		(start 313.706002 -301.439326)
		(end 312.600848 -302.54448)
		(width 0.18288)
		(layer "In6.Cu")
		(net "M_D_CPU0_SA_DQ<1>")
	)
	(segment
		(start 343.243662 -275.8948)
		(end 342.675718 -276.33168)
		(width 0.088646)
		(layer "In6.Cu")
		(net "M_D_CPU0_SA_DQ<1>")
	)
	(segment
		(start 278.143716 -314.918852)
		(end 277.326598 -314.918852)
		(width 0.18288)
		(layer "In6.Cu")
		(net "M_D_CPU0_SA_DQ<1>")
	)
	(segment
		(start 317.135764 -298.922186)
		(end 314.618624 -301.439326)
		(width 0.18288)
		(layer "In6.Cu")
		(net "M_D_CPU0_SA_DQ<1>")
	)
	(segment
		(start 287.208468 -314.893452)
		(end 285.360364 -316.741556)
		(width 0.18288)
		(layer "In6.Cu")
		(net "M_D_CPU0_SA_DQ<1>")
	)
	(segment
		(start 302.271176 -307.284374)
		(end 300.463712 -309.091838)
		(width 0.18288)
		(layer "In6.Cu")
		(net "M_D_CPU0_SA_DQ<1>")
	)
	(segment
		(start 339.212174 -276.390354)
		(end 339.20176 -276.384258)
		(width 0.088646)
		(layer "In6.Cu")
		(net "M_D_CPU0_SA_DQ<1>")
	)
	(segment
		(start 308.189884 -303.325784)
		(end 306.812442 -304.703226)
		(width 0.18288)
		(layer "In6.Cu")
		(net "M_D_CPU0_SA_DQ<1>")
	)
	(segment
		(start 293.099744 -312.443876)
		(end 292.653212 -312.443876)
		(width 0.18288)
		(layer "In6.Cu")
		(net "M_D_CPU0_SA_DQ<1>")
	)
	(segment
		(start 309.058056 -303.213008)
		(end 308.793642 -303.477422)
		(width 0.18288)
		(layer "In6.Cu")
		(net "M_D_CPU0_SA_DQ<1>")
	)
	(segment
		(start 342.675718 -276.33168)
		(end 342.586818 -276.384258)
		(width 0.088646)
		(layer "In6.Cu")
		(net "M_D_CPU0_SA_DQ<1>")
	)
	(segment
		(start 308.415944 -303.325784)
		(end 308.189884 -303.325784)
		(width 0.18288)
		(layer "In6.Cu")
		(net "M_D_CPU0_SA_DQ<1>")
	)
	(segment
		(start 296.215562 -311.641744)
		(end 293.901876 -311.641744)
		(width 0.18288)
		(layer "In6.Cu")
		(net "M_D_CPU0_SA_DQ<1>")
	)
	(segment
		(start 309.223918 -302.29175)
		(end 308.906418 -302.60925)
		(width 0.18288)
		(layer "In6.Cu")
		(net "M_D_CPU0_SA_DQ<1>")
	)
	(segment
		(start 338.357718 -277.198074)
		(end 338.348828 -277.203154)
		(width 0.088646)
		(layer "In6.Cu")
		(net "M_D_CPU0_SA_DQ<1>")
	)
	(segment
		(start 273.727418 -314.12434)
		(end 272.80997 -315.041788)
		(width 0.18288)
		(layer "In6.Cu")
		(net "M_D_CPU0_SA_DQ<1>")
	)
	(segment
		(start 332.502256 -281.976576)
		(end 332.054708 -281.976576)
		(width 0.18288)
		(layer "In6.Cu")
		(net "M_D_CPU0_SA_DQ<1>")
	)
	(segment
		(start 333.580486 -280.513028)
		(end 333.362046 -280.731468)
		(width 0.088646)
		(layer "In6.Cu")
		(net "M_D_CPU0_SA_DQ<1>")
	)
	(segment
		(start 306.812442 -304.703226)
		(end 306.365656 -304.703226)
		(width 0.18288)
		(layer "In6.Cu")
		(net "M_D_CPU0_SA_DQ<1>")
	)
	(segment
		(start 289.884612 -314.049664)
		(end 288.7472 -314.049664)
		(width 0.18288)
		(layer "In6.Cu")
		(net "M_D_CPU0_SA_DQ<1>")
	)
	(segment
		(start 300.463712 -309.091838)
		(end 298.765468 -309.091838)
		(width 0.18288)
		(layer "In6.Cu")
		(net "M_D_CPU0_SA_DQ<1>")
	)
	(segment
		(start 338.170266 -277.522432)
		(end 338.170266 -277.530052)
		(width 0.088646)
		(layer "In6.Cu")
		(net "M_D_CPU0_SA_DQ<1>")
	)
	(segment
		(start 306.365656 -304.703226)
		(end 304.602896 -306.465986)
		(width 0.18288)
		(layer "In6.Cu")
		(net "M_D_CPU0_SA_DQ<1>")
	)
	(segment
		(start 314.618624 -301.439326)
		(end 313.706002 -301.439326)
		(width 0.18288)
		(layer "In6.Cu")
		(net "M_D_CPU0_SA_DQ<1>")
	)
	(segment
		(start 338.639912 -276.708616)
		(end 338.639912 -276.72411)
		(width 0.088646)
		(layer "In6.Cu")
		(net "M_D_CPU0_SA_DQ<1>")
	)
	(segment
		(start 290.48456 -313.449716)
		(end 289.884612 -314.049664)
		(width 0.18288)
		(layer "In6.Cu")
		(net "M_D_CPU0_SA_DQ<1>")
	)
	(segment
		(start 287.903412 -314.893452)
		(end 287.208468 -314.893452)
		(width 0.18288)
		(layer "In6.Cu")
		(net "M_D_CPU0_SA_DQ<1>")
	)
	(segment
		(start 309.058056 -302.986948)
		(end 309.058056 -303.213008)
		(width 0.18288)
		(layer "In6.Cu")
		(net "M_D_CPU0_SA_DQ<1>")
	)
	(segment
		(start 308.567582 -303.477422)
		(end 308.415944 -303.325784)
		(width 0.18288)
		(layer "In6.Cu")
		(net "M_D_CPU0_SA_DQ<1>")
	)
	(segment
		(start 282.84043 -316.741556)
		(end 281.990546 -315.891672)
		(width 0.18288)
		(layer "In6.Cu")
		(net "M_D_CPU0_SA_DQ<1>")
	)
	(segment
		(start 304.602896 -306.465986)
		(end 303.821846 -306.465986)
		(width 0.18288)
		(layer "In6.Cu")
		(net "M_D_CPU0_SA_DQ<1>")
	)
	(segment
		(start 310.96839 -302.54448)
		(end 310.71566 -302.29175)
		(width 0.18288)
		(layer "In6.Cu")
		(net "M_D_CPU0_SA_DQ<1>")
	)
	(segment
		(start 292.653212 -312.443876)
		(end 291.647372 -313.449716)
		(width 0.18288)
		(layer "In6.Cu")
		(net "M_D_CPU0_SA_DQ<1>")
	)
	(segment
		(start 308.793642 -303.477422)
		(end 308.567582 -303.477422)
		(width 0.18288)
		(layer "In6.Cu")
		(net "M_D_CPU0_SA_DQ<1>")
	)
	(segment
		(start 332.758796 -281.976576)
		(end 332.502256 -281.976576)
		(width 0.088646)
		(layer "In6.Cu")
		(net "M_D_CPU0_SA_DQ<1>")
	)
	(segment
		(start 308.906418 -302.83531)
		(end 309.058056 -302.986948)
		(width 0.18288)
		(layer "In6.Cu")
		(net "M_D_CPU0_SA_DQ<1>")
	)
	(segment
		(start 303.821846 -306.465986)
		(end 303.003458 -307.284374)
		(width 0.18288)
		(layer "In6.Cu")
		(net "M_D_CPU0_SA_DQ<1>")
	)
	(segment
		(start 308.906418 -302.60925)
		(end 308.906418 -302.83531)
		(width 0.18288)
		(layer "In6.Cu")
		(net "M_D_CPU0_SA_DQ<1>")
	)
	(segment
		(start 267.49502 -315.041788)
		(end 266.873228 -315.66358)
		(width 0.18288)
		(layer "In6.Cu")
		(net "M_D_CPU0_SA_DQ<1>")
	)
	(segment
		(start 340.156546 -276.392894)
		(end 340.141814 -276.384258)
		(width 0.088646)
		(layer "In6.Cu")
		(net "M_D_CPU0_SA_DQ<1>")
	)
	(segment
		(start 298.765468 -309.091838)
		(end 296.215562 -311.641744)
		(width 0.18288)
		(layer "In6.Cu")
		(net "M_D_CPU0_SA_DQ<1>")
	)
	(segment
		(start 265.776202 -315.66358)
		(end 264.729214 -314.616592)
		(width 0.18288)
		(layer "In6.Cu")
		(net "M_D_CPU0_SA_DQ<1>")
	)
	(segment
		(start 337.700112 -278.336502)
		(end 337.700112 -278.346408)
		(width 0.088646)
		(layer "In6.Cu")
		(net "M_D_CPU0_SA_DQ<1>")
	)
	(segment
		(start 338.827364 -276.384258)
		(end 338.818474 -276.389338)
		(width 0.088646)
		(layer "In6.Cu")
		(net "M_D_CPU0_SA_DQ<1>")
	)
	(segment
		(start 303.003458 -307.284374)
		(end 302.271176 -307.284374)
		(width 0.18288)
		(layer "In6.Cu")
		(net "M_D_CPU0_SA_DQ<1>")
	)
	(segment
		(start 310.71566 -302.29175)
		(end 309.223918 -302.29175)
		(width 0.18288)
		(layer "In6.Cu")
		(net "M_D_CPU0_SA_DQ<1>")
	)
	(arc
		(start 334.97266 -278.82596)
		(mid 334.785462 -278.775817)
		(end 334.598264 -278.82596)
		(width 0.088646)
		(layer "In6.Cu")
		(net "M_D_CPU0_SA_DQ<1>")
	)
	(arc
		(start 340.707218 -276.384258)
		(mid 340.433019 -276.460093)
		(end 340.156546 -276.392894)
		(width 0.088646)
		(layer "In6.Cu")
		(net "M_D_CPU0_SA_DQ<1>")
	)
	(arc
		(start 342.021414 -276.384258)
		(mid 341.834216 -276.334115)
		(end 341.647018 -276.384258)
		(width 0.088646)
		(layer "In6.Cu")
		(net "M_D_CPU0_SA_DQ<1>")
	)
	(arc
		(start 339.20176 -276.384258)
		(mid 339.014562 -276.334115)
		(end 338.827364 -276.384258)
		(width 0.088646)
		(layer "In6.Cu")
		(net "M_D_CPU0_SA_DQ<1>")
	)
	(arc
		(start 335.91246 -278.82596)
		(mid 335.725262 -278.775817)
		(end 335.538064 -278.82596)
		(width 0.088646)
		(layer "In6.Cu")
		(net "M_D_CPU0_SA_DQ<1>")
	)
	(arc
		(start 339.767418 -276.384258)
		(mid 339.490605 -276.460128)
		(end 339.212174 -276.390354)
		(width 0.088646)
		(layer "In6.Cu")
		(net "M_D_CPU0_SA_DQ<1>")
	)
	(arc
		(start 338.639912 -276.72411)
		(mid 338.560542 -276.997844)
		(end 338.357718 -277.198074)
		(width 0.088646)
		(layer "In6.Cu")
		(net "M_D_CPU0_SA_DQ<1>")
	)
	(arc
		(start 336.477864 -278.82596)
		(mid 336.195162 -278.901736)
		(end 335.91246 -278.82596)
		(width 0.088646)
		(layer "In6.Cu")
		(net "M_D_CPU0_SA_DQ<1>")
	)
	(arc
		(start 334.589374 -278.83104)
		(mid 334.45846 -278.9674)
		(end 334.410812 -279.150318)
		(width 0.088646)
		(layer "In6.Cu")
		(net "M_D_CPU0_SA_DQ<1>")
	)
	(arc
		(start 341.647018 -276.384258)
		(mid 341.372819 -276.460093)
		(end 341.096346 -276.392894)
		(width 0.088646)
		(layer "In6.Cu")
		(net "M_D_CPU0_SA_DQ<1>")
	)
	(arc
		(start 337.417664 -278.82596)
		(mid 337.134962 -278.901736)
		(end 336.85226 -278.82596)
		(width 0.088646)
		(layer "In6.Cu")
		(net "M_D_CPU0_SA_DQ<1>")
	)
	(arc
		(start 338.348828 -277.203154)
		(mid 338.217914 -277.339514)
		(end 338.170266 -277.522432)
		(width 0.088646)
		(layer "In6.Cu")
		(net "M_D_CPU0_SA_DQ<1>")
	)
	(arc
		(start 341.081614 -276.384258)
		(mid 340.894416 -276.334115)
		(end 340.707218 -276.384258)
		(width 0.088646)
		(layer "In6.Cu")
		(net "M_D_CPU0_SA_DQ<1>")
	)
	(arc
		(start 337.700112 -278.346408)
		(mid 337.622001 -278.623357)
		(end 337.417664 -278.82596)
		(width 0.088646)
		(layer "In6.Cu")
		(net "M_D_CPU0_SA_DQ<1>")
	)
	(arc
		(start 335.538064 -278.82596)
		(mid 335.255362 -278.901736)
		(end 334.97266 -278.82596)
		(width 0.088646)
		(layer "In6.Cu")
		(net "M_D_CPU0_SA_DQ<1>")
	)
	(arc
		(start 338.170266 -277.530052)
		(mid 338.092637 -277.808465)
		(end 337.887564 -278.012144)
		(width 0.088646)
		(layer "In6.Cu")
		(net "M_D_CPU0_SA_DQ<1>")
	)
	(arc
		(start 334.410812 -279.160224)
		(mid 334.332701 -279.437173)
		(end 334.128364 -279.639776)
		(width 0.088646)
		(layer "In6.Cu")
		(net "M_D_CPU0_SA_DQ<1>")
	)
	(arc
		(start 333.940912 -279.982676)
		(mid 333.86075 -280.254865)
		(end 333.658464 -280.453846)
		(width 0.088646)
		(layer "In6.Cu")
		(net "M_D_CPU0_SA_DQ<1>")
	)
	(arc
		(start 340.141814 -276.384258)
		(mid 339.954616 -276.334115)
		(end 339.767418 -276.384258)
		(width 0.088646)
		(layer "In6.Cu")
		(net "M_D_CPU0_SA_DQ<1>")
	)
	(arc
		(start 338.818474 -276.389338)
		(mid 338.68756 -276.525698)
		(end 338.639912 -276.708616)
		(width 0.088646)
		(layer "In6.Cu")
		(net "M_D_CPU0_SA_DQ<1>")
	)
	(arc
		(start 333.658464 -280.453846)
		(mid 333.617534 -280.480879)
		(end 333.580486 -280.513028)
		(width 0.088646)
		(layer "In6.Cu")
		(net "M_D_CPU0_SA_DQ<1>")
	)
	(arc
		(start 336.85226 -278.82596)
		(mid 336.665062 -278.775817)
		(end 336.477864 -278.82596)
		(width 0.088646)
		(layer "In6.Cu")
		(net "M_D_CPU0_SA_DQ<1>")
	)
	(arc
		(start 342.586818 -276.384258)
		(mid 342.304116 -276.460034)
		(end 342.021414 -276.384258)
		(width 0.088646)
		(layer "In6.Cu")
		(net "M_D_CPU0_SA_DQ<1>")
	)
	(arc
		(start 337.878674 -278.017224)
		(mid 337.74776 -278.153584)
		(end 337.700112 -278.336502)
		(width 0.088646)
		(layer "In6.Cu")
		(net "M_D_CPU0_SA_DQ<1>")
	)
	(arc
		(start 334.119474 -279.644856)
		(mid 333.98856 -279.781216)
		(end 333.940912 -279.964134)
		(width 0.088646)
		(layer "In6.Cu")
		(net "M_D_CPU0_SA_DQ<1>")
	)
	(segment
		(start 267.724382 -295.06672)
		(end 266.90828 -295.06672)
		(width 0.20066)
		(layer "F.Cu")
		(net "M_D_CPU0_SA_DQ<19>")
	)
	(segment
		(start 264.825226 -295.491662)
		(end 262.752332 -295.491662)
		(width 0.1016)
		(layer "F.Cu")
		(net "M_D_CPU0_SA_DQ<19>")
	)
	(segment
		(start 261.87781 -295.06672)
		(end 260.180582 -295.06672)
		(width 0.20066)
		(layer "F.Cu")
		(net "M_D_CPU0_SA_DQ<19>")
	)
	(segment
		(start 265.369548 -295.491662)
		(end 264.825226 -295.491662)
		(width 0.20066)
		(layer "F.Cu")
		(net "M_D_CPU0_SA_DQ<19>")
	)
	(segment
		(start 265.64717 -295.062402)
		(end 265.518646 -295.190926)
		(width 0.20066)
		(layer "F.Cu")
		(net "M_D_CPU0_SA_DQ<19>")
	)
	(segment
		(start 266.90828 -295.06672)
		(end 266.700762 -295.274238)
		(width 0.20066)
		(layer "F.Cu")
		(net "M_D_CPU0_SA_DQ<19>")
	)
	(segment
		(start 262.514334 -295.491662)
		(end 262.50011 -295.505886)
		(width 0.101854)
		(layer "F.Cu")
		(net "M_D_CPU0_SA_DQ<19>")
	)
	(segment
		(start 262.50011 -295.505886)
		(end 262.146288 -295.505886)
		(width 0.20066)
		(layer "F.Cu")
		(net "M_D_CPU0_SA_DQ<19>")
	)
	(segment
		(start 268.829282 -295.06672)
		(end 267.724382 -295.06672)
		(width 0.20066)
		(layer "F.Cu")
		(net "M_D_CPU0_SA_DQ<19>")
	)
	(segment
		(start 266.700762 -295.274238)
		(end 266.25423 -295.274238)
		(width 0.20066)
		(layer "F.Cu")
		(net "M_D_CPU0_SA_DQ<19>")
	)
	(segment
		(start 266.042394 -295.062402)
		(end 265.64717 -295.062402)
		(width 0.20066)
		(layer "F.Cu")
		(net "M_D_CPU0_SA_DQ<19>")
	)
	(segment
		(start 262.146288 -295.505886)
		(end 262.003794 -295.363392)
		(width 0.20066)
		(layer "F.Cu")
		(net "M_D_CPU0_SA_DQ<19>")
	)
	(segment
		(start 262.003794 -295.192704)
		(end 261.87781 -295.06672)
		(width 0.20066)
		(layer "F.Cu")
		(net "M_D_CPU0_SA_DQ<19>")
	)
	(segment
		(start 265.518646 -295.342564)
		(end 265.369548 -295.491662)
		(width 0.20066)
		(layer "F.Cu")
		(net "M_D_CPU0_SA_DQ<19>")
	)
	(segment
		(start 265.518646 -295.190926)
		(end 265.518646 -295.342564)
		(width 0.20066)
		(layer "F.Cu")
		(net "M_D_CPU0_SA_DQ<19>")
	)
	(segment
		(start 262.003794 -295.363392)
		(end 262.003794 -295.192704)
		(width 0.20066)
		(layer "F.Cu")
		(net "M_D_CPU0_SA_DQ<19>")
	)
	(segment
		(start 266.25423 -295.274238)
		(end 266.042394 -295.062402)
		(width 0.20066)
		(layer "F.Cu")
		(net "M_D_CPU0_SA_DQ<19>")
	)
	(segment
		(start 262.752332 -295.491662)
		(end 262.514334 -295.491662)
		(width 0.101854)
		(layer "F.Cu")
		(net "M_D_CPU0_SA_DQ<19>")
	)
	(arc
		(start 348.412562 -272.917158)
		(mid 348.412625 -273.185128)
		(end 348.412816 -273.453098)
		(width 0.20066)
		(layer "F.Cu")
		(net "M_D_CPU0_SA_DQ<19>")
	)
	(segment
		(start 302.926496 -295.518078)
		(end 302.289464 -295.518078)
		(width 0.18288)
		(layer "In11.Cu")
		(net "M_D_CPU0_SA_DQ<19>")
	)
	(segment
		(start 286.442912 -296.653966)
		(end 286.127952 -296.653966)
		(width 0.18288)
		(layer "In11.Cu")
		(net "M_D_CPU0_SA_DQ<19>")
	)
	(segment
		(start 333.577946 -273.76882)
		(end 333.574136 -273.771106)
		(width 0.088646)
		(layer "In11.Cu")
		(net "M_D_CPU0_SA_DQ<19>")
	)
	(segment
		(start 312.917586 -291.23767)
		(end 311.83326 -292.321996)
		(width 0.18288)
		(layer "In11.Cu")
		(net "M_D_CPU0_SA_DQ<19>")
	)
	(segment
		(start 333.445866 -273.867118)
		(end 332.979522 -273.867118)
		(width 0.088646)
		(layer "In11.Cu")
		(net "M_D_CPU0_SA_DQ<19>")
	)
	(segment
		(start 306.71262 -293.125906)
		(end 305.785012 -293.510208)
		(width 0.18288)
		(layer "In11.Cu")
		(net "M_D_CPU0_SA_DQ<19>")
	)
	(segment
		(start 300.467014 -297.340528)
		(end 299.81525 -297.340528)
		(width 0.18288)
		(layer "In11.Cu")
		(net "M_D_CPU0_SA_DQ<19>")
	)
	(segment
		(start 338.272374 -273.77136)
		(end 338.26196 -273.777456)
		(width 0.088646)
		(layer "In11.Cu")
		(net "M_D_CPU0_SA_DQ<19>")
	)
	(segment
		(start 310.719216 -292.321996)
		(end 310.474106 -292.076886)
		(width 0.18288)
		(layer "In11.Cu")
		(net "M_D_CPU0_SA_DQ<19>")
	)
	(segment
		(start 282.964128 -297.192192)
		(end 282.057094 -298.099226)
		(width 0.18288)
		(layer "In11.Cu")
		(net "M_D_CPU0_SA_DQ<19>")
	)
	(segment
		(start 288.407094 -296.880026)
		(end 287.946592 -297.340528)
		(width 0.18288)
		(layer "In11.Cu")
		(net "M_D_CPU0_SA_DQ<19>")
	)
	(segment
		(start 273.645376 -296.393108)
		(end 272.906998 -295.65473)
		(width 0.18288)
		(layer "In11.Cu")
		(net "M_D_CPU0_SA_DQ<19>")
	)
	(segment
		(start 348.412816 -273.453098)
		(end 348.057216 -273.357848)
		(width 0.088646)
		(layer "In11.Cu")
		(net "M_D_CPU0_SA_DQ<19>")
	)
	(segment
		(start 299.81525 -297.340528)
		(end 299.666914 -297.192192)
		(width 0.18288)
		(layer "In11.Cu")
		(net "M_D_CPU0_SA_DQ<19>")
	)
	(segment
		(start 291.607494 -298.175426)
		(end 291.150294 -298.175426)
		(width 0.18288)
		(layer "In11.Cu")
		(net "M_D_CPU0_SA_DQ<19>")
	)
	(segment
		(start 270.671798 -295.65473)
		(end 269.417292 -295.65473)
		(width 0.18288)
		(layer "In11.Cu")
		(net "M_D_CPU0_SA_DQ<19>")
	)
	(segment
		(start 278.507952 -298.027852)
		(end 276.921468 -298.027852)
		(width 0.18288)
		(layer "In11.Cu")
		(net "M_D_CPU0_SA_DQ<19>")
	)
	(segment
		(start 304.539142 -294.756078)
		(end 303.688496 -294.756078)
		(width 0.18288)
		(layer "In11.Cu")
		(net "M_D_CPU0_SA_DQ<19>")
	)
	(segment
		(start 346.065348 -273.517106)
		(end 345.885262 -273.697192)
		(width 0.088646)
		(layer "In11.Cu")
		(net "M_D_CPU0_SA_DQ<19>")
	)
	(segment
		(start 284.579314 -297.192192)
		(end 282.964128 -297.192192)
		(width 0.18288)
		(layer "In11.Cu")
		(net "M_D_CPU0_SA_DQ<19>")
	)
	(segment
		(start 294.066976 -298.04233)
		(end 293.717472 -297.692826)
		(width 0.18288)
		(layer "In11.Cu")
		(net "M_D_CPU0_SA_DQ<19>")
	)
	(segment
		(start 286.127952 -296.653966)
		(end 285.934912 -296.847006)
		(width 0.18288)
		(layer "In11.Cu")
		(net "M_D_CPU0_SA_DQ<19>")
	)
	(segment
		(start 302.289464 -295.518078)
		(end 300.467014 -297.340528)
		(width 0.18288)
		(layer "In11.Cu")
		(net "M_D_CPU0_SA_DQ<19>")
	)
	(segment
		(start 305.785012 -293.510208)
		(end 304.539142 -294.756078)
		(width 0.18288)
		(layer "In11.Cu")
		(net "M_D_CPU0_SA_DQ<19>")
	)
	(segment
		(start 332.979522 -273.867118)
		(end 332.16215 -274.68449)
		(width 0.088646)
		(layer "In11.Cu")
		(net "M_D_CPU0_SA_DQ<19>")
	)
	(segment
		(start 271.565878 -295.46169)
		(end 271.565878 -295.076372)
		(width 0.18288)
		(layer "In11.Cu")
		(net "M_D_CPU0_SA_DQ<19>")
	)
	(segment
		(start 276.921468 -298.027852)
		(end 276.786594 -298.162726)
		(width 0.18288)
		(layer "In11.Cu")
		(net "M_D_CPU0_SA_DQ<19>")
	)
	(segment
		(start 274.432776 -296.393108)
		(end 273.645376 -296.393108)
		(width 0.18288)
		(layer "In11.Cu")
		(net "M_D_CPU0_SA_DQ<19>")
	)
	(segment
		(start 332.16215 -274.68449)
		(end 332.16215 -275.87321)
		(width 0.088646)
		(layer "In11.Cu")
		(net "M_D_CPU0_SA_DQ<19>")
	)
	(segment
		(start 291.150294 -298.175426)
		(end 289.854894 -296.880026)
		(width 0.18288)
		(layer "In11.Cu")
		(net "M_D_CPU0_SA_DQ<19>")
	)
	(segment
		(start 270.864838 -295.076372)
		(end 270.864838 -295.46169)
		(width 0.18288)
		(layer "In11.Cu")
		(net "M_D_CPU0_SA_DQ<19>")
	)
	(segment
		(start 289.854894 -296.880026)
		(end 288.407094 -296.880026)
		(width 0.18288)
		(layer "In11.Cu")
		(net "M_D_CPU0_SA_DQ<19>")
	)
	(segment
		(start 332.16215 -275.87321)
		(end 331.596746 -276.438614)
		(width 0.088646)
		(layer "In11.Cu")
		(net "M_D_CPU0_SA_DQ<19>")
	)
	(segment
		(start 280.95702 -298.099226)
		(end 280.900124 -298.04233)
		(width 0.18288)
		(layer "In11.Cu")
		(net "M_D_CPU0_SA_DQ<19>")
	)
	(segment
		(start 285.934912 -297.147488)
		(end 285.741872 -297.340528)
		(width 0.18288)
		(layer "In11.Cu")
		(net "M_D_CPU0_SA_DQ<19>")
	)
	(segment
		(start 271.372838 -294.883332)
		(end 271.057878 -294.883332)
		(width 0.18288)
		(layer "In11.Cu")
		(net "M_D_CPU0_SA_DQ<19>")
	)
	(segment
		(start 341.096346 -273.76882)
		(end 341.081614 -273.777456)
		(width 0.088646)
		(layer "In11.Cu")
		(net "M_D_CPU0_SA_DQ<19>")
	)
	(segment
		(start 342.031828 -273.77136)
		(end 342.021414 -273.777456)
		(width 0.088646)
		(layer "In11.Cu")
		(net "M_D_CPU0_SA_DQ<19>")
	)
	(segment
		(start 272.906998 -295.65473)
		(end 271.758918 -295.65473)
		(width 0.18288)
		(layer "In11.Cu")
		(net "M_D_CPU0_SA_DQ<19>")
	)
	(segment
		(start 293.717472 -297.692826)
		(end 292.090094 -297.692826)
		(width 0.18288)
		(layer "In11.Cu")
		(net "M_D_CPU0_SA_DQ<19>")
	)
	(segment
		(start 315.46165 -289.969448)
		(end 315.46165 -290.543234)
		(width 0.18288)
		(layer "In11.Cu")
		(net "M_D_CPU0_SA_DQ<19>")
	)
	(segment
		(start 271.057878 -294.883332)
		(end 270.864838 -295.076372)
		(width 0.18288)
		(layer "In11.Cu")
		(net "M_D_CPU0_SA_DQ<19>")
	)
	(segment
		(start 271.565878 -295.076372)
		(end 271.372838 -294.883332)
		(width 0.18288)
		(layer "In11.Cu")
		(net "M_D_CPU0_SA_DQ<19>")
	)
	(segment
		(start 346.228416 -273.222212)
		(end 346.161106 -273.338544)
		(width 0.088646)
		(layer "In11.Cu")
		(net "M_D_CPU0_SA_DQ<19>")
	)
	(segment
		(start 286.635952 -297.147488)
		(end 286.635952 -296.847006)
		(width 0.18288)
		(layer "In11.Cu")
		(net "M_D_CPU0_SA_DQ<19>")
	)
	(segment
		(start 308.88559 -292.076886)
		(end 307.83657 -293.125906)
		(width 0.18288)
		(layer "In11.Cu")
		(net "M_D_CPU0_SA_DQ<19>")
	)
	(segment
		(start 271.758918 -295.65473)
		(end 271.565878 -295.46169)
		(width 0.18288)
		(layer "In11.Cu")
		(net "M_D_CPU0_SA_DQ<19>")
	)
	(segment
		(start 284.72765 -297.340528)
		(end 284.579314 -297.192192)
		(width 0.18288)
		(layer "In11.Cu")
		(net "M_D_CPU0_SA_DQ<19>")
	)
	(segment
		(start 340.156546 -273.76882)
		(end 340.141814 -273.777456)
		(width 0.088646)
		(layer "In11.Cu")
		(net "M_D_CPU0_SA_DQ<19>")
	)
	(segment
		(start 270.864838 -295.46169)
		(end 270.671798 -295.65473)
		(width 0.18288)
		(layer "In11.Cu")
		(net "M_D_CPU0_SA_DQ<19>")
	)
	(segment
		(start 307.83657 -293.125906)
		(end 306.71262 -293.125906)
		(width 0.18288)
		(layer "In11.Cu")
		(net "M_D_CPU0_SA_DQ<19>")
	)
	(segment
		(start 269.417292 -295.65473)
		(end 268.829282 -295.06672)
		(width 0.18288)
		(layer "In11.Cu")
		(net "M_D_CPU0_SA_DQ<19>")
	)
	(segment
		(start 331.411326 -276.438614)
		(end 328.992484 -276.438614)
		(width 0.18288)
		(layer "In11.Cu")
		(net "M_D_CPU0_SA_DQ<19>")
	)
	(segment
		(start 299.666914 -297.192192)
		(end 298.167044 -297.192192)
		(width 0.18288)
		(layer "In11.Cu")
		(net "M_D_CPU0_SA_DQ<19>")
	)
	(segment
		(start 297.16857 -298.190666)
		(end 295.715182 -298.190666)
		(width 0.18288)
		(layer "In11.Cu")
		(net "M_D_CPU0_SA_DQ<19>")
	)
	(segment
		(start 295.715182 -298.190666)
		(end 295.566846 -298.04233)
		(width 0.18288)
		(layer "In11.Cu")
		(net "M_D_CPU0_SA_DQ<19>")
	)
	(segment
		(start 286.635952 -296.847006)
		(end 286.442912 -296.653966)
		(width 0.18288)
		(layer "In11.Cu")
		(net "M_D_CPU0_SA_DQ<19>")
	)
	(segment
		(start 314.767214 -291.23767)
		(end 312.917586 -291.23767)
		(width 0.18288)
		(layer "In11.Cu")
		(net "M_D_CPU0_SA_DQ<19>")
	)
	(segment
		(start 285.934912 -296.847006)
		(end 285.934912 -297.147488)
		(width 0.18288)
		(layer "In11.Cu")
		(net "M_D_CPU0_SA_DQ<19>")
	)
	(segment
		(start 276.202394 -298.162726)
		(end 274.432776 -296.393108)
		(width 0.18288)
		(layer "In11.Cu")
		(net "M_D_CPU0_SA_DQ<19>")
	)
	(segment
		(start 292.090094 -297.692826)
		(end 291.607494 -298.175426)
		(width 0.18288)
		(layer "In11.Cu")
		(net "M_D_CPU0_SA_DQ<19>")
	)
	(segment
		(start 328.992484 -276.438614)
		(end 315.46165 -289.969448)
		(width 0.18288)
		(layer "In11.Cu")
		(net "M_D_CPU0_SA_DQ<19>")
	)
	(segment
		(start 311.83326 -292.321996)
		(end 310.719216 -292.321996)
		(width 0.18288)
		(layer "In11.Cu")
		(net "M_D_CPU0_SA_DQ<19>")
	)
	(segment
		(start 346.351606 -273.125438)
		(end 346.290646 -273.160236)
		(width 0.088646)
		(layer "In11.Cu")
		(net "M_D_CPU0_SA_DQ<19>")
	)
	(segment
		(start 286.828992 -297.340528)
		(end 286.635952 -297.147488)
		(width 0.18288)
		(layer "In11.Cu")
		(net "M_D_CPU0_SA_DQ<19>")
	)
	(segment
		(start 331.596746 -276.438614)
		(end 331.411326 -276.438614)
		(width 0.088646)
		(layer "In11.Cu")
		(net "M_D_CPU0_SA_DQ<19>")
	)
	(segment
		(start 334.513428 -273.77136)
		(end 334.503014 -273.777456)
		(width 0.088646)
		(layer "In11.Cu")
		(net "M_D_CPU0_SA_DQ<19>")
	)
	(segment
		(start 278.52243 -298.04233)
		(end 278.507952 -298.027852)
		(width 0.18288)
		(layer "In11.Cu")
		(net "M_D_CPU0_SA_DQ<19>")
	)
	(segment
		(start 343.915746 -273.76882)
		(end 343.901014 -273.777456)
		(width 0.088646)
		(layer "In11.Cu")
		(net "M_D_CPU0_SA_DQ<19>")
	)
	(segment
		(start 342.971374 -273.77136)
		(end 342.96096 -273.777456)
		(width 0.088646)
		(layer "In11.Cu")
		(net "M_D_CPU0_SA_DQ<19>")
	)
	(segment
		(start 298.167044 -297.192192)
		(end 297.16857 -298.190666)
		(width 0.18288)
		(layer "In11.Cu")
		(net "M_D_CPU0_SA_DQ<19>")
	)
	(segment
		(start 303.688496 -294.756078)
		(end 302.926496 -295.518078)
		(width 0.18288)
		(layer "In11.Cu")
		(net "M_D_CPU0_SA_DQ<19>")
	)
	(segment
		(start 348.057216 -273.357848)
		(end 347.660214 -273.12874)
		(width 0.088646)
		(layer "In11.Cu")
		(net "M_D_CPU0_SA_DQ<19>")
	)
	(segment
		(start 315.46165 -290.543234)
		(end 314.767214 -291.23767)
		(width 0.18288)
		(layer "In11.Cu")
		(net "M_D_CPU0_SA_DQ<19>")
	)
	(segment
		(start 285.741872 -297.340528)
		(end 284.72765 -297.340528)
		(width 0.18288)
		(layer "In11.Cu")
		(net "M_D_CPU0_SA_DQ<19>")
	)
	(segment
		(start 344.855546 -273.76882)
		(end 344.840814 -273.777456)
		(width 0.088646)
		(layer "In11.Cu")
		(net "M_D_CPU0_SA_DQ<19>")
	)
	(segment
		(start 280.900124 -298.04233)
		(end 278.52243 -298.04233)
		(width 0.18288)
		(layer "In11.Cu")
		(net "M_D_CPU0_SA_DQ<19>")
	)
	(segment
		(start 282.057094 -298.099226)
		(end 280.95702 -298.099226)
		(width 0.18288)
		(layer "In11.Cu")
		(net "M_D_CPU0_SA_DQ<19>")
	)
	(segment
		(start 310.474106 -292.076886)
		(end 308.88559 -292.076886)
		(width 0.18288)
		(layer "In11.Cu")
		(net "M_D_CPU0_SA_DQ<19>")
	)
	(segment
		(start 287.946592 -297.340528)
		(end 286.828992 -297.340528)
		(width 0.18288)
		(layer "In11.Cu")
		(net "M_D_CPU0_SA_DQ<19>")
	)
	(segment
		(start 276.786594 -298.162726)
		(end 276.202394 -298.162726)
		(width 0.18288)
		(layer "In11.Cu")
		(net "M_D_CPU0_SA_DQ<19>")
	)
	(segment
		(start 347.291406 -273.125438)
		(end 347.279722 -273.132042)
		(width 0.088646)
		(layer "In11.Cu")
		(net "M_D_CPU0_SA_DQ<19>")
	)
	(segment
		(start 295.566846 -298.04233)
		(end 294.066976 -298.04233)
		(width 0.18288)
		(layer "In11.Cu")
		(net "M_D_CPU0_SA_DQ<19>")
	)
	(arc
		(start 345.406218 -273.777456)
		(mid 345.132019 -273.701621)
		(end 344.855546 -273.76882)
		(width 0.088646)
		(layer "In11.Cu")
		(net "M_D_CPU0_SA_DQ<19>")
	)
	(arc
		(start 347.279722 -273.132042)
		(mid 346.999617 -273.204484)
		(end 346.720414 -273.12874)
		(width 0.088646)
		(layer "In11.Cu")
		(net "M_D_CPU0_SA_DQ<19>")
	)
	(arc
		(start 343.901014 -273.777456)
		(mid 343.713816 -273.827599)
		(end 343.526618 -273.777456)
		(width 0.088646)
		(layer "In11.Cu")
		(net "M_D_CPU0_SA_DQ<19>")
	)
	(arc
		(start 344.466418 -273.777456)
		(mid 344.192219 -273.701621)
		(end 343.915746 -273.76882)
		(width 0.088646)
		(layer "In11.Cu")
		(net "M_D_CPU0_SA_DQ<19>")
	)
	(arc
		(start 346.161106 -273.338544)
		(mid 346.140915 -273.378227)
		(end 346.125038 -273.419824)
		(width 0.088646)
		(layer "In11.Cu")
		(net "M_D_CPU0_SA_DQ<19>")
	)
	(arc
		(start 334.503014 -273.777456)
		(mid 334.315816 -273.827599)
		(end 334.128618 -273.777456)
		(width 0.088646)
		(layer "In11.Cu")
		(net "M_D_CPU0_SA_DQ<19>")
	)
	(arc
		(start 345.780614 -273.777456)
		(mid 345.593416 -273.827599)
		(end 345.406218 -273.777456)
		(width 0.088646)
		(layer "In11.Cu")
		(net "M_D_CPU0_SA_DQ<19>")
	)
	(arc
		(start 340.707218 -273.777456)
		(mid 340.433019 -273.701621)
		(end 340.156546 -273.76882)
		(width 0.088646)
		(layer "In11.Cu")
		(net "M_D_CPU0_SA_DQ<19>")
	)
	(arc
		(start 338.26196 -273.777456)
		(mid 338.074762 -273.827599)
		(end 337.887564 -273.777456)
		(width 0.088646)
		(layer "In11.Cu")
		(net "M_D_CPU0_SA_DQ<19>")
	)
	(arc
		(start 334.128618 -273.777456)
		(mid 333.854419 -273.701621)
		(end 333.577946 -273.76882)
		(width 0.088646)
		(layer "In11.Cu")
		(net "M_D_CPU0_SA_DQ<19>")
	)
	(arc
		(start 340.141814 -273.777456)
		(mid 339.954616 -273.827599)
		(end 339.767418 -273.777456)
		(width 0.088646)
		(layer "In11.Cu")
		(net "M_D_CPU0_SA_DQ<19>")
	)
	(arc
		(start 342.96096 -273.777456)
		(mid 342.773762 -273.827599)
		(end 342.586564 -273.777456)
		(width 0.088646)
		(layer "In11.Cu")
		(net "M_D_CPU0_SA_DQ<19>")
	)
	(arc
		(start 342.586564 -273.777456)
		(mid 342.310005 -273.701713)
		(end 342.031828 -273.77136)
		(width 0.088646)
		(layer "In11.Cu")
		(net "M_D_CPU0_SA_DQ<19>")
	)
	(arc
		(start 343.526618 -273.777456)
		(mid 343.249805 -273.701586)
		(end 342.971374 -273.77136)
		(width 0.088646)
		(layer "In11.Cu")
		(net "M_D_CPU0_SA_DQ<19>")
	)
	(arc
		(start 347.660214 -273.12874)
		(mid 347.47626 -273.078611)
		(end 347.291406 -273.125438)
		(width 0.088646)
		(layer "In11.Cu")
		(net "M_D_CPU0_SA_DQ<19>")
	)
	(arc
		(start 346.125038 -273.419824)
		(mid 346.100967 -273.47201)
		(end 346.065348 -273.517106)
		(width 0.088646)
		(layer "In11.Cu")
		(net "M_D_CPU0_SA_DQ<19>")
	)
	(arc
		(start 337.887564 -273.777456)
		(mid 337.604862 -273.70168)
		(end 337.32216 -273.777456)
		(width 0.088646)
		(layer "In11.Cu")
		(net "M_D_CPU0_SA_DQ<19>")
	)
	(arc
		(start 345.885262 -273.697192)
		(mid 345.835565 -273.740749)
		(end 345.780614 -273.777456)
		(width 0.088646)
		(layer "In11.Cu")
		(net "M_D_CPU0_SA_DQ<19>")
	)
	(arc
		(start 335.068164 -273.777456)
		(mid 334.791605 -273.701713)
		(end 334.513428 -273.77136)
		(width 0.088646)
		(layer "In11.Cu")
		(net "M_D_CPU0_SA_DQ<19>")
	)
	(arc
		(start 336.007964 -273.777456)
		(mid 335.725262 -273.70168)
		(end 335.44256 -273.777456)
		(width 0.088646)
		(layer "In11.Cu")
		(net "M_D_CPU0_SA_DQ<19>")
	)
	(arc
		(start 338.827618 -273.777456)
		(mid 338.550805 -273.701586)
		(end 338.272374 -273.77136)
		(width 0.088646)
		(layer "In11.Cu")
		(net "M_D_CPU0_SA_DQ<19>")
	)
	(arc
		(start 342.021414 -273.777456)
		(mid 341.834216 -273.827599)
		(end 341.647018 -273.777456)
		(width 0.088646)
		(layer "In11.Cu")
		(net "M_D_CPU0_SA_DQ<19>")
	)
	(arc
		(start 335.44256 -273.777456)
		(mid 335.255362 -273.827599)
		(end 335.068164 -273.777456)
		(width 0.088646)
		(layer "In11.Cu")
		(net "M_D_CPU0_SA_DQ<19>")
	)
	(arc
		(start 341.081614 -273.777456)
		(mid 340.894416 -273.827599)
		(end 340.707218 -273.777456)
		(width 0.088646)
		(layer "In11.Cu")
		(net "M_D_CPU0_SA_DQ<19>")
	)
	(arc
		(start 337.32216 -273.777456)
		(mid 337.134962 -273.827599)
		(end 336.947764 -273.777456)
		(width 0.088646)
		(layer "In11.Cu")
		(net "M_D_CPU0_SA_DQ<19>")
	)
	(arc
		(start 346.290646 -273.160236)
		(mid 346.255456 -273.187129)
		(end 346.228416 -273.222212)
		(width 0.088646)
		(layer "In11.Cu")
		(net "M_D_CPU0_SA_DQ<19>")
	)
	(arc
		(start 339.767418 -273.777456)
		(mid 339.484716 -273.70168)
		(end 339.202014 -273.777456)
		(width 0.088646)
		(layer "In11.Cu")
		(net "M_D_CPU0_SA_DQ<19>")
	)
	(arc
		(start 336.947764 -273.777456)
		(mid 336.665062 -273.70168)
		(end 336.38236 -273.777456)
		(width 0.088646)
		(layer "In11.Cu")
		(net "M_D_CPU0_SA_DQ<19>")
	)
	(arc
		(start 341.647018 -273.777456)
		(mid 341.372819 -273.701621)
		(end 341.096346 -273.76882)
		(width 0.088646)
		(layer "In11.Cu")
		(net "M_D_CPU0_SA_DQ<19>")
	)
	(arc
		(start 339.202014 -273.777456)
		(mid 339.014816 -273.827599)
		(end 338.827618 -273.777456)
		(width 0.088646)
		(layer "In11.Cu")
		(net "M_D_CPU0_SA_DQ<19>")
	)
	(arc
		(start 346.720414 -273.12874)
		(mid 346.53646 -273.078611)
		(end 346.351606 -273.125438)
		(width 0.088646)
		(layer "In11.Cu")
		(net "M_D_CPU0_SA_DQ<19>")
	)
	(arc
		(start 333.574136 -273.771106)
		(mid 333.506585 -273.814548)
		(end 333.445866 -273.867118)
		(width 0.088646)
		(layer "In11.Cu")
		(net "M_D_CPU0_SA_DQ<19>")
	)
	(arc
		(start 336.38236 -273.777456)
		(mid 336.195162 -273.827599)
		(end 336.007964 -273.777456)
		(width 0.088646)
		(layer "In11.Cu")
		(net "M_D_CPU0_SA_DQ<19>")
	)
	(arc
		(start 344.840814 -273.777456)
		(mid 344.653616 -273.827599)
		(end 344.466418 -273.777456)
		(width 0.088646)
		(layer "In11.Cu")
		(net "M_D_CPU0_SA_DQ<19>")
	)
	(segment
		(start 262.50011 -296.33164)
		(end 261.762748 -296.33164)
		(width 0.20066)
		(layer "F.Cu")
		(net "M_D_CPU0_SA_DQ<18>")
	)
	(segment
		(start 265.458194 -296.3418)
		(end 264.825226 -296.3418)
		(width 0.20066)
		(layer "F.Cu")
		(net "M_D_CPU0_SA_DQ<18>")
	)
	(segment
		(start 262.51027 -296.3418)
		(end 262.50011 -296.33164)
		(width 0.101854)
		(layer "F.Cu")
		(net "M_D_CPU0_SA_DQ<18>")
	)
	(segment
		(start 347.942916 -274.26666)
		(end 347.942662 -274.266914)
		(width 0.20066)
		(layer "F.Cu")
		(net "M_D_CPU0_SA_DQ<18>")
	)
	(segment
		(start 264.825226 -296.3418)
		(end 262.765286 -296.3418)
		(width 0.1016)
		(layer "F.Cu")
		(net "M_D_CPU0_SA_DQ<18>")
	)
	(segment
		(start 261.762748 -296.33164)
		(end 261.327646 -296.766742)
		(width 0.20066)
		(layer "F.Cu")
		(net "M_D_CPU0_SA_DQ<18>")
	)
	(segment
		(start 267.724382 -296.766742)
		(end 266.409678 -296.766742)
		(width 0.20066)
		(layer "F.Cu")
		(net "M_D_CPU0_SA_DQ<18>")
	)
	(segment
		(start 266.197842 -296.978578)
		(end 265.769344 -296.978578)
		(width 0.20066)
		(layer "F.Cu")
		(net "M_D_CPU0_SA_DQ<18>")
	)
	(segment
		(start 266.409678 -296.766742)
		(end 266.197842 -296.978578)
		(width 0.20066)
		(layer "F.Cu")
		(net "M_D_CPU0_SA_DQ<18>")
	)
	(segment
		(start 347.942916 -273.730974)
		(end 347.942916 -274.26666)
		(width 0.20066)
		(layer "F.Cu")
		(net "M_D_CPU0_SA_DQ<18>")
	)
	(segment
		(start 265.769344 -296.978578)
		(end 265.601958 -296.811192)
		(width 0.20066)
		(layer "F.Cu")
		(net "M_D_CPU0_SA_DQ<18>")
	)
	(segment
		(start 265.601958 -296.485564)
		(end 265.458194 -296.3418)
		(width 0.20066)
		(layer "F.Cu")
		(net "M_D_CPU0_SA_DQ<18>")
	)
	(segment
		(start 261.327646 -296.766742)
		(end 260.180582 -296.766742)
		(width 0.20066)
		(layer "F.Cu")
		(net "M_D_CPU0_SA_DQ<18>")
	)
	(segment
		(start 262.765286 -296.3418)
		(end 262.51027 -296.3418)
		(width 0.101854)
		(layer "F.Cu")
		(net "M_D_CPU0_SA_DQ<18>")
	)
	(segment
		(start 268.829282 -296.766742)
		(end 267.724382 -296.766742)
		(width 0.20066)
		(layer "F.Cu")
		(net "M_D_CPU0_SA_DQ<18>")
	)
	(segment
		(start 265.601958 -296.811192)
		(end 265.601958 -296.485564)
		(width 0.20066)
		(layer "F.Cu")
		(net "M_D_CPU0_SA_DQ<18>")
	)
	(segment
		(start 302.792638 -297.245786)
		(end 301.693072 -297.701208)
		(width 0.18288)
		(layer "In11.Cu")
		(net "M_D_CPU0_SA_DQ<18>")
	)
	(segment
		(start 301.693072 -297.701208)
		(end 300.380654 -299.013626)
		(width 0.18288)
		(layer "In11.Cu")
		(net "M_D_CPU0_SA_DQ<18>")
	)
	(segment
		(start 298.028614 -298.891706)
		(end 297.308778 -299.611542)
		(width 0.18288)
		(layer "In11.Cu")
		(net "M_D_CPU0_SA_DQ<18>")
	)
	(segment
		(start 299.461174 -298.891706)
		(end 298.028614 -298.891706)
		(width 0.18288)
		(layer "In11.Cu")
		(net "M_D_CPU0_SA_DQ<18>")
	)
	(segment
		(start 316.488826 -290.95319)
		(end 314.452 -292.990016)
		(width 0.18288)
		(layer "In11.Cu")
		(net "M_D_CPU0_SA_DQ<18>")
	)
	(segment
		(start 287.797494 -299.064426)
		(end 286.821372 -299.064426)
		(width 0.18288)
		(layer "In11.Cu")
		(net "M_D_CPU0_SA_DQ<18>")
	)
	(segment
		(start 286.120332 -298.450762)
		(end 285.927292 -298.643802)
		(width 0.18288)
		(layer "In11.Cu")
		(net "M_D_CPU0_SA_DQ<18>")
	)
	(segment
		(start 332.604872 -277.052786)
		(end 331.848714 -277.808944)
		(width 0.088646)
		(layer "In11.Cu")
		(net "M_D_CPU0_SA_DQ<18>")
	)
	(segment
		(start 308.13121 -294.360346)
		(end 307.243734 -294.360346)
		(width 0.18288)
		(layer "In11.Cu")
		(net "M_D_CPU0_SA_DQ<18>")
	)
	(segment
		(start 343.056464 -274.591272)
		(end 343.041732 -274.582636)
		(width 0.088646)
		(layer "In11.Cu")
		(net "M_D_CPU0_SA_DQ<18>")
	)
	(segment
		(start 272.979642 -297.360594)
		(end 271.602962 -297.360594)
		(width 0.18288)
		(layer "In11.Cu")
		(net "M_D_CPU0_SA_DQ<18>")
	)
	(segment
		(start 278.634444 -299.648626)
		(end 277.078694 -299.648626)
		(width 0.18288)
		(layer "In11.Cu")
		(net "M_D_CPU0_SA_DQ<18>")
	)
	(segment
		(start 316.488826 -290.379658)
		(end 316.488826 -290.95319)
		(width 0.18288)
		(layer "In11.Cu")
		(net "M_D_CPU0_SA_DQ<18>")
	)
	(segment
		(start 331.42301 -277.808944)
		(end 331.316584 -277.702518)
		(width 0.088646)
		(layer "In11.Cu")
		(net "M_D_CPU0_SA_DQ<18>")
	)
	(segment
		(start 285.028894 -299.064426)
		(end 284.856174 -298.891706)
		(width 0.18288)
		(layer "In11.Cu")
		(net "M_D_CPU0_SA_DQ<18>")
	)
	(segment
		(start 304.480976 -296.391584)
		(end 303.401984 -296.838624)
		(width 0.18288)
		(layer "In11.Cu")
		(net "M_D_CPU0_SA_DQ<18>")
	)
	(segment
		(start 310.689498 -293.97833)
		(end 310.689498 -293.696136)
		(width 0.18288)
		(layer "In11.Cu")
		(net "M_D_CPU0_SA_DQ<18>")
	)
	(segment
		(start 296.851324 -299.801026)
		(end 295.727882 -299.801026)
		(width 0.18288)
		(layer "In11.Cu")
		(net "M_D_CPU0_SA_DQ<18>")
	)
	(segment
		(start 344.936064 -274.591272)
		(end 344.921332 -274.582636)
		(width 0.088646)
		(layer "In11.Cu")
		(net "M_D_CPU0_SA_DQ<18>")
	)
	(segment
		(start 278.727662 -299.741844)
		(end 278.634444 -299.648626)
		(width 0.18288)
		(layer "In11.Cu")
		(net "M_D_CPU0_SA_DQ<18>")
	)
	(segment
		(start 303.401984 -296.838624)
		(end 302.792638 -297.245786)
		(width 0.18288)
		(layer "In11.Cu")
		(net "M_D_CPU0_SA_DQ<18>")
	)
	(segment
		(start 310.882538 -294.17137)
		(end 310.689498 -293.97833)
		(width 0.18288)
		(layer "In11.Cu")
		(net "M_D_CPU0_SA_DQ<18>")
	)
	(segment
		(start 288.254694 -298.607226)
		(end 287.797494 -299.064426)
		(width 0.18288)
		(layer "In11.Cu")
		(net "M_D_CPU0_SA_DQ<18>")
	)
	(segment
		(start 286.821372 -299.064426)
		(end 286.628332 -298.871386)
		(width 0.18288)
		(layer "In11.Cu")
		(net "M_D_CPU0_SA_DQ<18>")
	)
	(segment
		(start 342.116664 -274.591272)
		(end 342.101932 -274.582636)
		(width 0.088646)
		(layer "In11.Cu")
		(net "M_D_CPU0_SA_DQ<18>")
	)
	(segment
		(start 285.927292 -298.643802)
		(end 285.927292 -298.871386)
		(width 0.18288)
		(layer "In11.Cu")
		(net "M_D_CPU0_SA_DQ<18>")
	)
	(segment
		(start 310.496458 -293.503096)
		(end 308.98846 -293.503096)
		(width 0.18288)
		(layer "In11.Cu")
		(net "M_D_CPU0_SA_DQ<18>")
	)
	(segment
		(start 306.057554 -294.815006)
		(end 304.480976 -296.391584)
		(width 0.18288)
		(layer "In11.Cu")
		(net "M_D_CPU0_SA_DQ<18>")
	)
	(segment
		(start 271.602962 -297.360594)
		(end 271.409922 -297.167554)
		(width 0.18288)
		(layer "In11.Cu")
		(net "M_D_CPU0_SA_DQ<18>")
	)
	(segment
		(start 286.628332 -298.643802)
		(end 286.435292 -298.450762)
		(width 0.18288)
		(layer "In11.Cu")
		(net "M_D_CPU0_SA_DQ<18>")
	)
	(segment
		(start 286.435292 -298.450762)
		(end 286.120332 -298.450762)
		(width 0.18288)
		(layer "In11.Cu")
		(net "M_D_CPU0_SA_DQ<18>")
	)
	(segment
		(start 276.301708 -299.801026)
		(end 276.010624 -299.680376)
		(width 0.18288)
		(layer "In11.Cu")
		(net "M_D_CPU0_SA_DQ<18>")
	)
	(segment
		(start 280.5811 -299.741844)
		(end 278.727662 -299.741844)
		(width 0.18288)
		(layer "In11.Cu")
		(net "M_D_CPU0_SA_DQ<18>")
	)
	(segment
		(start 286.628332 -298.871386)
		(end 286.628332 -298.643802)
		(width 0.18288)
		(layer "In11.Cu")
		(net "M_D_CPU0_SA_DQ<18>")
	)
	(segment
		(start 270.002254 -297.360594)
		(end 269.408402 -296.766742)
		(width 0.18288)
		(layer "In11.Cu")
		(net "M_D_CPU0_SA_DQ<18>")
	)
	(segment
		(start 332.604872 -274.854162)
		(end 332.604872 -277.052786)
		(width 0.088646)
		(layer "In11.Cu")
		(net "M_D_CPU0_SA_DQ<18>")
	)
	(segment
		(start 295.727882 -299.801026)
		(end 295.6687 -299.741844)
		(width 0.18288)
		(layer "In11.Cu")
		(net "M_D_CPU0_SA_DQ<18>")
	)
	(segment
		(start 311.390538 -293.696136)
		(end 311.390538 -293.97833)
		(width 0.18288)
		(layer "In11.Cu")
		(net "M_D_CPU0_SA_DQ<18>")
	)
	(segment
		(start 339.297518 -274.591272)
		(end 339.287104 -274.585176)
		(width 0.088646)
		(layer "In11.Cu")
		(net "M_D_CPU0_SA_DQ<18>")
	)
	(segment
		(start 299.583094 -299.013626)
		(end 299.461174 -298.891706)
		(width 0.18288)
		(layer "In11.Cu")
		(net "M_D_CPU0_SA_DQ<18>")
	)
	(segment
		(start 270.901922 -296.684446)
		(end 270.708882 -296.877486)
		(width 0.18288)
		(layer "In11.Cu")
		(net "M_D_CPU0_SA_DQ<18>")
	)
	(segment
		(start 331.316584 -277.543768)
		(end 331.227684 -277.454868)
		(width 0.088646)
		(layer "In11.Cu")
		(net "M_D_CPU0_SA_DQ<18>")
	)
	(segment
		(start 276.926294 -299.801026)
		(end 276.301708 -299.801026)
		(width 0.18288)
		(layer "In11.Cu")
		(net "M_D_CPU0_SA_DQ<18>")
	)
	(segment
		(start 283.271214 -298.891706)
		(end 282.35021 -299.81271)
		(width 0.18288)
		(layer "In11.Cu")
		(net "M_D_CPU0_SA_DQ<18>")
	)
	(segment
		(start 311.583578 -293.503096)
		(end 311.390538 -293.696136)
		(width 0.18288)
		(layer "In11.Cu")
		(net "M_D_CPU0_SA_DQ<18>")
	)
	(segment
		(start 332.943708 -274.515326)
		(end 332.604872 -274.854162)
		(width 0.088646)
		(layer "In11.Cu")
		(net "M_D_CPU0_SA_DQ<18>")
	)
	(segment
		(start 310.689498 -293.696136)
		(end 310.496458 -293.503096)
		(width 0.18288)
		(layer "In11.Cu")
		(net "M_D_CPU0_SA_DQ<18>")
	)
	(segment
		(start 306.789074 -294.815006)
		(end 306.057554 -294.815006)
		(width 0.18288)
		(layer "In11.Cu")
		(net "M_D_CPU0_SA_DQ<18>")
	)
	(segment
		(start 282.35021 -299.81271)
		(end 280.651966 -299.81271)
		(width 0.18288)
		(layer "In11.Cu")
		(net "M_D_CPU0_SA_DQ<18>")
	)
	(segment
		(start 284.856174 -298.891706)
		(end 283.271214 -298.891706)
		(width 0.18288)
		(layer "In11.Cu")
		(net "M_D_CPU0_SA_DQ<18>")
	)
	(segment
		(start 270.708882 -297.167554)
		(end 270.515842 -297.360594)
		(width 0.18288)
		(layer "In11.Cu")
		(net "M_D_CPU0_SA_DQ<18>")
	)
	(segment
		(start 347.942662 -274.266914)
		(end 347.64599 -274.266914)
		(width 0.088646)
		(layer "In11.Cu")
		(net "M_D_CPU0_SA_DQ<18>")
	)
	(segment
		(start 297.308778 -299.611542)
		(end 296.851324 -299.801026)
		(width 0.18288)
		(layer "In11.Cu")
		(net "M_D_CPU0_SA_DQ<18>")
	)
	(segment
		(start 311.197498 -294.17137)
		(end 310.882538 -294.17137)
		(width 0.18288)
		(layer "In11.Cu")
		(net "M_D_CPU0_SA_DQ<18>")
	)
	(segment
		(start 292.242494 -299.547026)
		(end 291.988494 -299.801026)
		(width 0.18288)
		(layer "In11.Cu")
		(net "M_D_CPU0_SA_DQ<18>")
	)
	(segment
		(start 290.739068 -299.5676)
		(end 289.778694 -298.607226)
		(width 0.18288)
		(layer "In11.Cu")
		(net "M_D_CPU0_SA_DQ<18>")
	)
	(segment
		(start 300.380654 -299.013626)
		(end 299.583094 -299.013626)
		(width 0.18288)
		(layer "In11.Cu")
		(net "M_D_CPU0_SA_DQ<18>")
	)
	(segment
		(start 291.302694 -299.801026)
		(end 290.739068 -299.5676)
		(width 0.18288)
		(layer "In11.Cu")
		(net "M_D_CPU0_SA_DQ<18>")
	)
	(segment
		(start 314.452 -292.990016)
		(end 313.213242 -293.503096)
		(width 0.18288)
		(layer "In11.Cu")
		(net "M_D_CPU0_SA_DQ<18>")
	)
	(segment
		(start 331.121258 -277.454868)
		(end 329.413616 -277.454868)
		(width 0.18288)
		(layer "In11.Cu")
		(net "M_D_CPU0_SA_DQ<18>")
	)
	(segment
		(start 343.996264 -274.591272)
		(end 343.981532 -274.582636)
		(width 0.088646)
		(layer "In11.Cu")
		(net "M_D_CPU0_SA_DQ<18>")
	)
	(segment
		(start 271.216882 -296.684446)
		(end 270.901922 -296.684446)
		(width 0.18288)
		(layer "In11.Cu")
		(net "M_D_CPU0_SA_DQ<18>")
	)
	(segment
		(start 271.409922 -297.167554)
		(end 271.409922 -296.877486)
		(width 0.18288)
		(layer "In11.Cu")
		(net "M_D_CPU0_SA_DQ<18>")
	)
	(segment
		(start 276.010624 -299.680376)
		(end 274.531074 -298.200826)
		(width 0.18288)
		(layer "In11.Cu")
		(net "M_D_CPU0_SA_DQ<18>")
	)
	(segment
		(start 271.409922 -296.877486)
		(end 271.216882 -296.684446)
		(width 0.18288)
		(layer "In11.Cu")
		(net "M_D_CPU0_SA_DQ<18>")
	)
	(segment
		(start 293.620444 -299.547026)
		(end 292.242494 -299.547026)
		(width 0.18288)
		(layer "In11.Cu")
		(net "M_D_CPU0_SA_DQ<18>")
	)
	(segment
		(start 346.251784 -274.59051)
		(end 346.25026 -274.591272)
		(width 0.088646)
		(layer "In11.Cu")
		(net "M_D_CPU0_SA_DQ<18>")
	)
	(segment
		(start 293.815262 -299.741844)
		(end 293.620444 -299.547026)
		(width 0.18288)
		(layer "In11.Cu")
		(net "M_D_CPU0_SA_DQ<18>")
	)
	(segment
		(start 311.390538 -293.97833)
		(end 311.197498 -294.17137)
		(width 0.18288)
		(layer "In11.Cu")
		(net "M_D_CPU0_SA_DQ<18>")
	)
	(segment
		(start 277.078694 -299.648626)
		(end 276.926294 -299.801026)
		(width 0.18288)
		(layer "In11.Cu")
		(net "M_D_CPU0_SA_DQ<18>")
	)
	(segment
		(start 274.531074 -298.200826)
		(end 274.241768 -298.200826)
		(width 0.18288)
		(layer "In11.Cu")
		(net "M_D_CPU0_SA_DQ<18>")
	)
	(segment
		(start 280.651966 -299.81271)
		(end 280.5811 -299.741844)
		(width 0.18288)
		(layer "In11.Cu")
		(net "M_D_CPU0_SA_DQ<18>")
	)
	(segment
		(start 289.778694 -298.607226)
		(end 288.254694 -298.607226)
		(width 0.18288)
		(layer "In11.Cu")
		(net "M_D_CPU0_SA_DQ<18>")
	)
	(segment
		(start 307.243734 -294.360346)
		(end 306.789074 -294.815006)
		(width 0.18288)
		(layer "In11.Cu")
		(net "M_D_CPU0_SA_DQ<18>")
	)
	(segment
		(start 273.558762 -297.939714)
		(end 272.979642 -297.360594)
		(width 0.18288)
		(layer "In11.Cu")
		(net "M_D_CPU0_SA_DQ<18>")
	)
	(segment
		(start 270.515842 -297.360594)
		(end 270.002254 -297.360594)
		(width 0.18288)
		(layer "In11.Cu")
		(net "M_D_CPU0_SA_DQ<18>")
	)
	(segment
		(start 331.316584 -277.702518)
		(end 331.316584 -277.543768)
		(width 0.088646)
		(layer "In11.Cu")
		(net "M_D_CPU0_SA_DQ<18>")
	)
	(segment
		(start 346.545662 -274.217384)
		(end 346.37599 -274.47367)
		(width 0.088646)
		(layer "In11.Cu")
		(net "M_D_CPU0_SA_DQ<18>")
	)
	(segment
		(start 345.875864 -274.591272)
		(end 345.861132 -274.582636)
		(width 0.088646)
		(layer "In11.Cu")
		(net "M_D_CPU0_SA_DQ<18>")
	)
	(segment
		(start 291.988494 -299.801026)
		(end 291.302694 -299.801026)
		(width 0.18288)
		(layer "In11.Cu")
		(net "M_D_CPU0_SA_DQ<18>")
	)
	(segment
		(start 341.176864 -274.591272)
		(end 341.162132 -274.582636)
		(width 0.088646)
		(layer "In11.Cu")
		(net "M_D_CPU0_SA_DQ<18>")
	)
	(segment
		(start 274.241768 -298.200826)
		(end 273.558762 -297.939714)
		(width 0.18288)
		(layer "In11.Cu")
		(net "M_D_CPU0_SA_DQ<18>")
	)
	(segment
		(start 331.848714 -277.808944)
		(end 331.42301 -277.808944)
		(width 0.088646)
		(layer "In11.Cu")
		(net "M_D_CPU0_SA_DQ<18>")
	)
	(segment
		(start 285.927292 -298.871386)
		(end 285.734252 -299.064426)
		(width 0.18288)
		(layer "In11.Cu")
		(net "M_D_CPU0_SA_DQ<18>")
	)
	(segment
		(start 270.708882 -296.877486)
		(end 270.708882 -297.167554)
		(width 0.18288)
		(layer "In11.Cu")
		(net "M_D_CPU0_SA_DQ<18>")
	)
	(segment
		(start 334.047592 -274.582636)
		(end 334.03286 -274.591272)
		(width 0.088646)
		(layer "In11.Cu")
		(net "M_D_CPU0_SA_DQ<18>")
	)
	(segment
		(start 313.213242 -293.503096)
		(end 311.583578 -293.503096)
		(width 0.18288)
		(layer "In11.Cu")
		(net "M_D_CPU0_SA_DQ<18>")
	)
	(segment
		(start 285.734252 -299.064426)
		(end 285.028894 -299.064426)
		(width 0.18288)
		(layer "In11.Cu")
		(net "M_D_CPU0_SA_DQ<18>")
	)
	(segment
		(start 334.987392 -274.582636)
		(end 334.97266 -274.591272)
		(width 0.088646)
		(layer "In11.Cu")
		(net "M_D_CPU0_SA_DQ<18>")
	)
	(segment
		(start 329.413616 -277.454868)
		(end 316.488826 -290.379658)
		(width 0.18288)
		(layer "In11.Cu")
		(net "M_D_CPU0_SA_DQ<18>")
	)
	(segment
		(start 339.682328 -274.585176)
		(end 339.671914 -274.591272)
		(width 0.088646)
		(layer "In11.Cu")
		(net "M_D_CPU0_SA_DQ<18>")
	)
	(segment
		(start 333.375508 -274.515326)
		(end 332.943708 -274.515326)
		(width 0.088646)
		(layer "In11.Cu")
		(net "M_D_CPU0_SA_DQ<18>")
	)
	(segment
		(start 331.227684 -277.454868)
		(end 331.121258 -277.454868)
		(width 0.088646)
		(layer "In11.Cu")
		(net "M_D_CPU0_SA_DQ<18>")
	)
	(segment
		(start 308.98846 -293.503096)
		(end 308.13121 -294.360346)
		(width 0.18288)
		(layer "In11.Cu")
		(net "M_D_CPU0_SA_DQ<18>")
	)
	(segment
		(start 295.6687 -299.741844)
		(end 293.815262 -299.741844)
		(width 0.18288)
		(layer "In11.Cu")
		(net "M_D_CPU0_SA_DQ<18>")
	)
	(segment
		(start 269.408402 -296.766742)
		(end 268.829282 -296.766742)
		(width 0.18288)
		(layer "In11.Cu")
		(net "M_D_CPU0_SA_DQ<18>")
	)
	(arc
		(start 343.981532 -274.582636)
		(mid 343.705057 -274.515316)
		(end 343.43086 -274.591272)
		(width 0.088646)
		(layer "In11.Cu")
		(net "M_D_CPU0_SA_DQ<18>")
	)
	(arc
		(start 334.598264 -274.591272)
		(mid 334.324065 -274.515437)
		(end 334.047592 -274.582636)
		(width 0.088646)
		(layer "In11.Cu")
		(net "M_D_CPU0_SA_DQ<18>")
	)
	(arc
		(start 346.72651 -274.014184)
		(mid 346.675802 -274.068478)
		(end 346.623894 -274.121626)
		(width 0.088646)
		(layer "In11.Cu")
		(net "M_D_CPU0_SA_DQ<18>")
	)
	(arc
		(start 339.671914 -274.591272)
		(mid 339.484716 -274.641415)
		(end 339.297518 -274.591272)
		(width 0.088646)
		(layer "In11.Cu")
		(net "M_D_CPU0_SA_DQ<18>")
	)
	(arc
		(start 337.417664 -274.591272)
		(mid 337.134962 -274.515496)
		(end 336.85226 -274.591272)
		(width 0.088646)
		(layer "In11.Cu")
		(net "M_D_CPU0_SA_DQ<18>")
	)
	(arc
		(start 342.101932 -274.582636)
		(mid 341.825457 -274.515316)
		(end 341.55126 -274.591272)
		(width 0.088646)
		(layer "In11.Cu")
		(net "M_D_CPU0_SA_DQ<18>")
	)
	(arc
		(start 341.55126 -274.591272)
		(mid 341.364062 -274.641415)
		(end 341.176864 -274.591272)
		(width 0.088646)
		(layer "In11.Cu")
		(net "M_D_CPU0_SA_DQ<18>")
	)
	(arc
		(start 346.37599 -274.47367)
		(mid 346.320686 -274.539317)
		(end 346.251784 -274.59051)
		(width 0.088646)
		(layer "In11.Cu")
		(net "M_D_CPU0_SA_DQ<18>")
	)
	(arc
		(start 340.61146 -274.591272)
		(mid 340.424262 -274.641415)
		(end 340.237064 -274.591272)
		(width 0.088646)
		(layer "In11.Cu")
		(net "M_D_CPU0_SA_DQ<18>")
	)
	(arc
		(start 344.37066 -274.591272)
		(mid 344.183462 -274.641415)
		(end 343.996264 -274.591272)
		(width 0.088646)
		(layer "In11.Cu")
		(net "M_D_CPU0_SA_DQ<18>")
	)
	(arc
		(start 334.03286 -274.591272)
		(mid 333.845662 -274.641415)
		(end 333.658464 -274.591272)
		(width 0.088646)
		(layer "In11.Cu")
		(net "M_D_CPU0_SA_DQ<18>")
	)
	(arc
		(start 340.237064 -274.591272)
		(mid 339.960505 -274.515529)
		(end 339.682328 -274.585176)
		(width 0.088646)
		(layer "In11.Cu")
		(net "M_D_CPU0_SA_DQ<18>")
	)
	(arc
		(start 333.658464 -274.591272)
		(mid 333.521992 -274.534649)
		(end 333.375508 -274.515326)
		(width 0.088646)
		(layer "In11.Cu")
		(net "M_D_CPU0_SA_DQ<18>")
	)
	(arc
		(start 334.97266 -274.591272)
		(mid 334.785462 -274.641415)
		(end 334.598264 -274.591272)
		(width 0.088646)
		(layer "In11.Cu")
		(net "M_D_CPU0_SA_DQ<18>")
	)
	(arc
		(start 339.287104 -274.585176)
		(mid 339.008672 -274.51533)
		(end 338.73186 -274.591272)
		(width 0.088646)
		(layer "In11.Cu")
		(net "M_D_CPU0_SA_DQ<18>")
	)
	(arc
		(start 337.79206 -274.591272)
		(mid 337.604862 -274.641415)
		(end 337.417664 -274.591272)
		(width 0.088646)
		(layer "In11.Cu")
		(net "M_D_CPU0_SA_DQ<18>")
	)
	(arc
		(start 341.162132 -274.582636)
		(mid 340.885657 -274.515316)
		(end 340.61146 -274.591272)
		(width 0.088646)
		(layer "In11.Cu")
		(net "M_D_CPU0_SA_DQ<18>")
	)
	(arc
		(start 335.91246 -274.591272)
		(mid 335.725262 -274.641415)
		(end 335.538064 -274.591272)
		(width 0.088646)
		(layer "In11.Cu")
		(net "M_D_CPU0_SA_DQ<18>")
	)
	(arc
		(start 345.861132 -274.582636)
		(mid 345.584657 -274.515316)
		(end 345.31046 -274.591272)
		(width 0.088646)
		(layer "In11.Cu")
		(net "M_D_CPU0_SA_DQ<18>")
	)
	(arc
		(start 347.32849 -274.082002)
		(mid 347.044776 -273.894799)
		(end 346.72651 -274.014184)
		(width 0.088646)
		(layer "In11.Cu")
		(net "M_D_CPU0_SA_DQ<18>")
	)
	(arc
		(start 347.64599 -274.266914)
		(mid 347.462342 -274.217239)
		(end 347.32849 -274.082002)
		(width 0.088646)
		(layer "In11.Cu")
		(net "M_D_CPU0_SA_DQ<18>")
	)
	(arc
		(start 346.623894 -274.121626)
		(mid 346.582372 -274.167539)
		(end 346.545662 -274.217384)
		(width 0.088646)
		(layer "In11.Cu")
		(net "M_D_CPU0_SA_DQ<18>")
	)
	(arc
		(start 342.49106 -274.591272)
		(mid 342.303862 -274.641415)
		(end 342.116664 -274.591272)
		(width 0.088646)
		(layer "In11.Cu")
		(net "M_D_CPU0_SA_DQ<18>")
	)
	(arc
		(start 345.31046 -274.591272)
		(mid 345.123262 -274.641415)
		(end 344.936064 -274.591272)
		(width 0.088646)
		(layer "In11.Cu")
		(net "M_D_CPU0_SA_DQ<18>")
	)
	(arc
		(start 343.041732 -274.582636)
		(mid 342.765257 -274.515316)
		(end 342.49106 -274.591272)
		(width 0.088646)
		(layer "In11.Cu")
		(net "M_D_CPU0_SA_DQ<18>")
	)
	(arc
		(start 346.25026 -274.591272)
		(mid 346.063062 -274.641415)
		(end 345.875864 -274.591272)
		(width 0.088646)
		(layer "In11.Cu")
		(net "M_D_CPU0_SA_DQ<18>")
	)
	(arc
		(start 336.85226 -274.591272)
		(mid 336.665062 -274.641415)
		(end 336.477864 -274.591272)
		(width 0.088646)
		(layer "In11.Cu")
		(net "M_D_CPU0_SA_DQ<18>")
	)
	(arc
		(start 344.921332 -274.582636)
		(mid 344.644857 -274.515316)
		(end 344.37066 -274.591272)
		(width 0.088646)
		(layer "In11.Cu")
		(net "M_D_CPU0_SA_DQ<18>")
	)
	(arc
		(start 343.43086 -274.591272)
		(mid 343.243662 -274.641415)
		(end 343.056464 -274.591272)
		(width 0.088646)
		(layer "In11.Cu")
		(net "M_D_CPU0_SA_DQ<18>")
	)
	(arc
		(start 338.357464 -274.591272)
		(mid 338.074762 -274.515496)
		(end 337.79206 -274.591272)
		(width 0.088646)
		(layer "In11.Cu")
		(net "M_D_CPU0_SA_DQ<18>")
	)
	(arc
		(start 335.538064 -274.591272)
		(mid 335.263865 -274.515437)
		(end 334.987392 -274.582636)
		(width 0.088646)
		(layer "In11.Cu")
		(net "M_D_CPU0_SA_DQ<18>")
	)
	(arc
		(start 338.73186 -274.591272)
		(mid 338.544662 -274.641415)
		(end 338.357464 -274.591272)
		(width 0.088646)
		(layer "In11.Cu")
		(net "M_D_CPU0_SA_DQ<18>")
	)
	(arc
		(start 336.477864 -274.591272)
		(mid 336.195162 -274.515496)
		(end 335.91246 -274.591272)
		(width 0.088646)
		(layer "In11.Cu")
		(net "M_D_CPU0_SA_DQ<18>")
	)
	(segment
		(start 258.28498 -295.645332)
		(end 258.28498 -295.9735)
		(width 0.20066)
		(layer "F.Cu")
		(net "M_D_CPU0_SA_DQ<17>")
	)
	(segment
		(start 258.28498 -295.9735)
		(end 258.130548 -296.127932)
		(width 0.20066)
		(layer "F.Cu")
		(net "M_D_CPU0_SA_DQ<17>")
	)
	(segment
		(start 258.44754 -295.482772)
		(end 258.28498 -295.645332)
		(width 0.20066)
		(layer "F.Cu")
		(net "M_D_CPU0_SA_DQ<17>")
	)
	(segment
		(start 261.560056 -295.491662)
		(end 261.381494 -295.491662)
		(width 0.20066)
		(layer "F.Cu")
		(net "M_D_CPU0_SA_DQ<17>")
	)
	(segment
		(start 257.414776 -295.916604)
		(end 256.080514 -295.916604)
		(width 0.20066)
		(layer "F.Cu")
		(net "M_D_CPU0_SA_DQ<17>")
	)
	(segment
		(start 259.056378 -295.482772)
		(end 258.44754 -295.482772)
		(width 0.20066)
		(layer "F.Cu")
		(net "M_D_CPU0_SA_DQ<17>")
	)
	(segment
		(start 257.626104 -296.127932)
		(end 257.414776 -295.916604)
		(width 0.20066)
		(layer "F.Cu")
		(net "M_D_CPU0_SA_DQ<17>")
	)
	(segment
		(start 263.624314 -295.916604)
		(end 261.984998 -295.916604)
		(width 0.20066)
		(layer "F.Cu")
		(net "M_D_CPU0_SA_DQ<17>")
	)
	(segment
		(start 264.729214 -295.916604)
		(end 263.624314 -295.916604)
		(width 0.20066)
		(layer "F.Cu")
		(net "M_D_CPU0_SA_DQ<17>")
	)
	(segment
		(start 261.050786 -295.491662)
		(end 259.065268 -295.491662)
		(width 0.1016)
		(layer "F.Cu")
		(net "M_D_CPU0_SA_DQ<17>")
	)
	(segment
		(start 259.065268 -295.491662)
		(end 259.056378 -295.482772)
		(width 0.1016)
		(layer "F.Cu")
		(net "M_D_CPU0_SA_DQ<17>")
	)
	(segment
		(start 261.381494 -295.491662)
		(end 261.050786 -295.491662)
		(width 0.101854)
		(layer "F.Cu")
		(net "M_D_CPU0_SA_DQ<17>")
	)
	(segment
		(start 258.130548 -296.127932)
		(end 257.626104 -296.127932)
		(width 0.20066)
		(layer "F.Cu")
		(net "M_D_CPU0_SA_DQ<17>")
	)
	(segment
		(start 261.984998 -295.916604)
		(end 261.560056 -295.491662)
		(width 0.20066)
		(layer "F.Cu")
		(net "M_D_CPU0_SA_DQ<17>")
	)
	(arc
		(start 346.532962 -272.917158)
		(mid 346.533025 -273.185128)
		(end 346.533216 -273.453098)
		(width 0.20066)
		(layer "F.Cu")
		(net "M_D_CPU0_SA_DQ<17>")
	)
	(segment
		(start 341.176864 -273.942556)
		(end 341.162132 -273.951192)
		(width 0.088646)
		(layer "In11.Cu")
		(net "M_D_CPU0_SA_DQ<17>")
	)
	(segment
		(start 278.49576 -298.892214)
		(end 278.323548 -299.064426)
		(width 0.18288)
		(layer "In11.Cu")
		(net "M_D_CPU0_SA_DQ<17>")
	)
	(segment
		(start 312.891932 -291.984684)
		(end 312.805318 -292.193726)
		(width 0.18288)
		(layer "In11.Cu")
		(net "M_D_CPU0_SA_DQ<17>")
	)
	(segment
		(start 342.116664 -273.942556)
		(end 342.101932 -273.951192)
		(width 0.088646)
		(layer "In11.Cu")
		(net "M_D_CPU0_SA_DQ<17>")
	)
	(segment
		(start 274.157186 -296.905426)
		(end 273.217894 -296.905426)
		(width 0.18288)
		(layer "In11.Cu")
		(net "M_D_CPU0_SA_DQ<17>")
	)
	(segment
		(start 266.80668 -296.55262)
		(end 265.8999 -296.55262)
		(width 0.18288)
		(layer "In11.Cu")
		(net "M_D_CPU0_SA_DQ<17>")
	)
	(segment
		(start 296.171112 -298.708826)
		(end 295.987724 -298.892214)
		(width 0.18288)
		(layer "In11.Cu")
		(net "M_D_CPU0_SA_DQ<17>")
	)
	(segment
		(start 292.318694 -299.013626)
		(end 292.029388 -298.72432)
		(width 0.18288)
		(layer "In11.Cu")
		(net "M_D_CPU0_SA_DQ<17>")
	)
	(segment
		(start 277.383494 -299.064426)
		(end 276.991318 -298.67225)
		(width 0.18288)
		(layer "In11.Cu")
		(net "M_D_CPU0_SA_DQ<17>")
	)
	(segment
		(start 293.583106 -298.892214)
		(end 293.461694 -299.013626)
		(width 0.18288)
		(layer "In11.Cu")
		(net "M_D_CPU0_SA_DQ<17>")
	)
	(segment
		(start 331.411326 -276.946868)
		(end 329.20305 -276.946868)
		(width 0.18288)
		(layer "In11.Cu")
		(net "M_D_CPU0_SA_DQ<17>")
	)
	(segment
		(start 282.412694 -298.632626)
		(end 281.159712 -298.632626)
		(width 0.18288)
		(layer "In11.Cu")
		(net "M_D_CPU0_SA_DQ<17>")
	)
	(segment
		(start 290.792408 -298.72432)
		(end 290.185094 -298.117006)
		(width 0.18288)
		(layer "In11.Cu")
		(net "M_D_CPU0_SA_DQ<17>")
	)
	(segment
		(start 339.297518 -273.942556)
		(end 339.287104 -273.948652)
		(width 0.088646)
		(layer "In11.Cu")
		(net "M_D_CPU0_SA_DQ<17>")
	)
	(segment
		(start 331.601064 -276.946868)
		(end 331.411326 -276.946868)
		(width 0.088646)
		(layer "In11.Cu")
		(net "M_D_CPU0_SA_DQ<17>")
	)
	(segment
		(start 283.003244 -298.042076)
		(end 282.412694 -298.632626)
		(width 0.18288)
		(layer "In11.Cu")
		(net "M_D_CPU0_SA_DQ<17>")
	)
	(segment
		(start 295.987724 -298.892214)
		(end 293.583106 -298.892214)
		(width 0.18288)
		(layer "In11.Cu")
		(net "M_D_CPU0_SA_DQ<17>")
	)
	(segment
		(start 312.273442 -292.985698)
		(end 308.73065 -292.985698)
		(width 0.18288)
		(layer "In11.Cu")
		(net "M_D_CPU0_SA_DQ<17>")
	)
	(segment
		(start 268.026134 -295.945814)
		(end 267.866114 -295.785794)
		(width 0.18288)
		(layer "In11.Cu")
		(net "M_D_CPU0_SA_DQ<17>")
	)
	(segment
		(start 303.037494 -296.219626)
		(end 302.351694 -296.219626)
		(width 0.18288)
		(layer "In11.Cu")
		(net "M_D_CPU0_SA_DQ<17>")
	)
	(segment
		(start 343.996264 -273.942556)
		(end 343.981532 -273.951192)
		(width 0.088646)
		(layer "In11.Cu")
		(net "M_D_CPU0_SA_DQ<17>")
	)
	(segment
		(start 312.946288 -292.534086)
		(end 312.859928 -292.742874)
		(width 0.18288)
		(layer "In11.Cu")
		(net "M_D_CPU0_SA_DQ<17>")
	)
	(segment
		(start 329.20305 -276.946868)
		(end 315.980826 -290.169092)
		(width 0.18288)
		(layer "In11.Cu")
		(net "M_D_CPU0_SA_DQ<17>")
	)
	(segment
		(start 288.559494 -298.099226)
		(end 288.34461 -297.884342)
		(width 0.18288)
		(layer "In11.Cu")
		(net "M_D_CPU0_SA_DQ<17>")
	)
	(segment
		(start 269.68958 -296.172128)
		(end 269.520416 -296.341292)
		(width 0.18288)
		(layer "In11.Cu")
		(net "M_D_CPU0_SA_DQ<17>")
	)
	(segment
		(start 268.200632 -296.341292)
		(end 268.026134 -296.166794)
		(width 0.18288)
		(layer "In11.Cu")
		(net "M_D_CPU0_SA_DQ<17>")
	)
	(segment
		(start 292.029388 -298.72432)
		(end 290.792408 -298.72432)
		(width 0.18288)
		(layer "In11.Cu")
		(net "M_D_CPU0_SA_DQ<17>")
	)
	(segment
		(start 303.901094 -295.356026)
		(end 303.037494 -296.219626)
		(width 0.18288)
		(layer "In11.Cu")
		(net "M_D_CPU0_SA_DQ<17>")
	)
	(segment
		(start 314.076588 -292.490652)
		(end 313.563508 -292.278054)
		(width 0.18288)
		(layer "In11.Cu")
		(net "M_D_CPU0_SA_DQ<17>")
	)
	(segment
		(start 313.563508 -292.278054)
		(end 313.422538 -291.937948)
		(width 0.18288)
		(layer "In11.Cu")
		(net "M_D_CPU0_SA_DQ<17>")
	)
	(segment
		(start 288.34461 -297.884342)
		(end 284.919674 -297.884342)
		(width 0.18288)
		(layer "In11.Cu")
		(net "M_D_CPU0_SA_DQ<17>")
	)
	(segment
		(start 276.991318 -298.67225)
		(end 275.92401 -298.67225)
		(width 0.18288)
		(layer "In11.Cu")
		(net "M_D_CPU0_SA_DQ<17>")
	)
	(segment
		(start 267.866114 -295.785794)
		(end 267.573506 -295.785794)
		(width 0.18288)
		(layer "In11.Cu")
		(net "M_D_CPU0_SA_DQ<17>")
	)
	(segment
		(start 334.598264 -273.942556)
		(end 334.583532 -273.951192)
		(width 0.088646)
		(layer "In11.Cu")
		(net "M_D_CPU0_SA_DQ<17>")
	)
	(segment
		(start 265.8999 -296.55262)
		(end 265.264138 -295.916858)
		(width 0.18288)
		(layer "In11.Cu")
		(net "M_D_CPU0_SA_DQ<17>")
	)
	(segment
		(start 290.185094 -298.117006)
		(end 290.152074 -298.117006)
		(width 0.18288)
		(layer "In11.Cu")
		(net "M_D_CPU0_SA_DQ<17>")
	)
	(segment
		(start 346.533216 -273.453098)
		(end 345.954096 -273.897344)
		(width 0.088646)
		(layer "In11.Cu")
		(net "M_D_CPU0_SA_DQ<17>")
	)
	(segment
		(start 340.237064 -273.942556)
		(end 340.22665 -273.948652)
		(width 0.088646)
		(layer "In11.Cu")
		(net "M_D_CPU0_SA_DQ<17>")
	)
	(segment
		(start 344.936064 -273.942556)
		(end 344.921332 -273.951192)
		(width 0.088646)
		(layer "In11.Cu")
		(net "M_D_CPU0_SA_DQ<17>")
	)
	(segment
		(start 308.73065 -292.985698)
		(end 307.996082 -293.720266)
		(width 0.18288)
		(layer "In11.Cu")
		(net "M_D_CPU0_SA_DQ<17>")
	)
	(segment
		(start 306.606448 -293.720266)
		(end 306.217574 -293.881302)
		(width 0.18288)
		(layer "In11.Cu")
		(net "M_D_CPU0_SA_DQ<17>")
	)
	(segment
		(start 299.633894 -297.896026)
		(end 299.487844 -298.042076)
		(width 0.18288)
		(layer "In11.Cu")
		(net "M_D_CPU0_SA_DQ<17>")
	)
	(segment
		(start 304.74285 -295.356026)
		(end 303.901094 -295.356026)
		(width 0.18288)
		(layer "In11.Cu")
		(net "M_D_CPU0_SA_DQ<17>")
	)
	(segment
		(start 267.573506 -295.785794)
		(end 266.80668 -296.55262)
		(width 0.18288)
		(layer "In11.Cu")
		(net "M_D_CPU0_SA_DQ<17>")
	)
	(segment
		(start 312.859928 -292.742874)
		(end 312.273442 -292.985698)
		(width 0.18288)
		(layer "In11.Cu")
		(net "M_D_CPU0_SA_DQ<17>")
	)
	(segment
		(start 275.92401 -298.67225)
		(end 274.157186 -296.905426)
		(width 0.18288)
		(layer "In11.Cu")
		(net "M_D_CPU0_SA_DQ<17>")
	)
	(segment
		(start 300.675294 -297.896026)
		(end 299.633894 -297.896026)
		(width 0.18288)
		(layer "In11.Cu")
		(net "M_D_CPU0_SA_DQ<17>")
	)
	(segment
		(start 298.090844 -298.042076)
		(end 297.424094 -298.708826)
		(width 0.18288)
		(layer "In11.Cu")
		(net "M_D_CPU0_SA_DQ<17>")
	)
	(segment
		(start 297.424094 -298.708826)
		(end 296.171112 -298.708826)
		(width 0.18288)
		(layer "In11.Cu")
		(net "M_D_CPU0_SA_DQ<17>")
	)
	(segment
		(start 278.323548 -299.064426)
		(end 277.383494 -299.064426)
		(width 0.18288)
		(layer "In11.Cu")
		(net "M_D_CPU0_SA_DQ<17>")
	)
	(segment
		(start 333.580486 -274.001738)
		(end 333.518256 -274.063968)
		(width 0.088646)
		(layer "In11.Cu")
		(net "M_D_CPU0_SA_DQ<17>")
	)
	(segment
		(start 290.152074 -298.117006)
		(end 290.134294 -298.099226)
		(width 0.18288)
		(layer "In11.Cu")
		(net "M_D_CPU0_SA_DQ<17>")
	)
	(segment
		(start 302.351694 -296.219626)
		(end 300.675294 -297.896026)
		(width 0.18288)
		(layer "In11.Cu")
		(net "M_D_CPU0_SA_DQ<17>")
	)
	(segment
		(start 333.09052 -274.063968)
		(end 332.394814 -274.759674)
		(width 0.088646)
		(layer "In11.Cu")
		(net "M_D_CPU0_SA_DQ<17>")
	)
	(segment
		(start 306.217574 -293.881302)
		(end 304.74285 -295.356026)
		(width 0.18288)
		(layer "In11.Cu")
		(net "M_D_CPU0_SA_DQ<17>")
	)
	(segment
		(start 313.422538 -291.937948)
		(end 313.213496 -291.851334)
		(width 0.18288)
		(layer "In11.Cu")
		(net "M_D_CPU0_SA_DQ<17>")
	)
	(segment
		(start 299.487844 -298.042076)
		(end 298.090844 -298.042076)
		(width 0.18288)
		(layer "In11.Cu")
		(net "M_D_CPU0_SA_DQ<17>")
	)
	(segment
		(start 265.264138 -295.916858)
		(end 264.729468 -295.916858)
		(width 0.18288)
		(layer "In11.Cu")
		(net "M_D_CPU0_SA_DQ<17>")
	)
	(segment
		(start 268.026134 -296.166794)
		(end 268.026134 -295.945814)
		(width 0.18288)
		(layer "In11.Cu")
		(net "M_D_CPU0_SA_DQ<17>")
	)
	(segment
		(start 269.520416 -296.341292)
		(end 268.200632 -296.341292)
		(width 0.18288)
		(layer "In11.Cu")
		(net "M_D_CPU0_SA_DQ<17>")
	)
	(segment
		(start 307.996082 -293.720266)
		(end 306.606448 -293.720266)
		(width 0.18288)
		(layer "In11.Cu")
		(net "M_D_CPU0_SA_DQ<17>")
	)
	(segment
		(start 293.461694 -299.013626)
		(end 292.318694 -299.013626)
		(width 0.18288)
		(layer "In11.Cu")
		(net "M_D_CPU0_SA_DQ<17>")
	)
	(segment
		(start 313.213496 -291.851334)
		(end 312.891932 -291.984684)
		(width 0.18288)
		(layer "In11.Cu")
		(net "M_D_CPU0_SA_DQ<17>")
	)
	(segment
		(start 284.919674 -297.884342)
		(end 284.76194 -298.042076)
		(width 0.18288)
		(layer "In11.Cu")
		(net "M_D_CPU0_SA_DQ<17>")
	)
	(segment
		(start 345.954096 -273.897344)
		(end 345.875864 -273.942556)
		(width 0.088646)
		(layer "In11.Cu")
		(net "M_D_CPU0_SA_DQ<17>")
	)
	(segment
		(start 272.484596 -296.172128)
		(end 269.68958 -296.172128)
		(width 0.18288)
		(layer "In11.Cu")
		(net "M_D_CPU0_SA_DQ<17>")
	)
	(segment
		(start 281.159712 -298.632626)
		(end 280.900124 -298.892214)
		(width 0.18288)
		(layer "In11.Cu")
		(net "M_D_CPU0_SA_DQ<17>")
	)
	(segment
		(start 264.729468 -295.916858)
		(end 264.729214 -295.916604)
		(width 0.18288)
		(layer "In11.Cu")
		(net "M_D_CPU0_SA_DQ<17>")
	)
	(segment
		(start 314.343288 -292.380162)
		(end 314.076588 -292.490652)
		(width 0.18288)
		(layer "In11.Cu")
		(net "M_D_CPU0_SA_DQ<17>")
	)
	(segment
		(start 332.394814 -274.759674)
		(end 332.394814 -276.153118)
		(width 0.088646)
		(layer "In11.Cu")
		(net "M_D_CPU0_SA_DQ<17>")
	)
	(segment
		(start 332.394814 -276.153118)
		(end 331.601064 -276.946868)
		(width 0.088646)
		(layer "In11.Cu")
		(net "M_D_CPU0_SA_DQ<17>")
	)
	(segment
		(start 315.980826 -290.169092)
		(end 315.980826 -290.742624)
		(width 0.18288)
		(layer "In11.Cu")
		(net "M_D_CPU0_SA_DQ<17>")
	)
	(segment
		(start 333.518256 -274.063968)
		(end 333.09052 -274.063968)
		(width 0.088646)
		(layer "In11.Cu")
		(net "M_D_CPU0_SA_DQ<17>")
	)
	(segment
		(start 345.875864 -273.942556)
		(end 345.861132 -273.951192)
		(width 0.088646)
		(layer "In11.Cu")
		(net "M_D_CPU0_SA_DQ<17>")
	)
	(segment
		(start 290.134294 -298.099226)
		(end 288.559494 -298.099226)
		(width 0.18288)
		(layer "In11.Cu")
		(net "M_D_CPU0_SA_DQ<17>")
	)
	(segment
		(start 284.76194 -298.042076)
		(end 283.003244 -298.042076)
		(width 0.18288)
		(layer "In11.Cu")
		(net "M_D_CPU0_SA_DQ<17>")
	)
	(segment
		(start 273.217894 -296.905426)
		(end 272.484596 -296.172128)
		(width 0.18288)
		(layer "In11.Cu")
		(net "M_D_CPU0_SA_DQ<17>")
	)
	(segment
		(start 280.900124 -298.892214)
		(end 278.49576 -298.892214)
		(width 0.18288)
		(layer "In11.Cu")
		(net "M_D_CPU0_SA_DQ<17>")
	)
	(segment
		(start 312.805318 -292.193726)
		(end 312.946288 -292.534086)
		(width 0.18288)
		(layer "In11.Cu")
		(net "M_D_CPU0_SA_DQ<17>")
	)
	(segment
		(start 315.980826 -290.742624)
		(end 314.343288 -292.380162)
		(width 0.18288)
		(layer "In11.Cu")
		(net "M_D_CPU0_SA_DQ<17>")
	)
	(arc
		(start 333.658464 -273.942556)
		(mid 333.617534 -273.969589)
		(end 333.580486 -274.001738)
		(width 0.088646)
		(layer "In11.Cu")
		(net "M_D_CPU0_SA_DQ<17>")
	)
	(arc
		(start 343.056464 -273.942556)
		(mid 342.773762 -274.018332)
		(end 342.49106 -273.942556)
		(width 0.088646)
		(layer "In11.Cu")
		(net "M_D_CPU0_SA_DQ<17>")
	)
	(arc
		(start 338.357464 -273.942556)
		(mid 338.074762 -274.018332)
		(end 337.79206 -273.942556)
		(width 0.088646)
		(layer "In11.Cu")
		(net "M_D_CPU0_SA_DQ<17>")
	)
	(arc
		(start 340.22665 -273.948652)
		(mid 339.948472 -274.018375)
		(end 339.671914 -273.942556)
		(width 0.088646)
		(layer "In11.Cu")
		(net "M_D_CPU0_SA_DQ<17>")
	)
	(arc
		(start 334.03286 -273.942556)
		(mid 333.845662 -273.892413)
		(end 333.658464 -273.942556)
		(width 0.088646)
		(layer "In11.Cu")
		(net "M_D_CPU0_SA_DQ<17>")
	)
	(arc
		(start 343.981532 -273.951192)
		(mid 343.705057 -274.018512)
		(end 343.43086 -273.942556)
		(width 0.088646)
		(layer "In11.Cu")
		(net "M_D_CPU0_SA_DQ<17>")
	)
	(arc
		(start 335.538064 -273.942556)
		(mid 335.255362 -274.018332)
		(end 334.97266 -273.942556)
		(width 0.088646)
		(layer "In11.Cu")
		(net "M_D_CPU0_SA_DQ<17>")
	)
	(arc
		(start 338.73186 -273.942556)
		(mid 338.544662 -273.892413)
		(end 338.357464 -273.942556)
		(width 0.088646)
		(layer "In11.Cu")
		(net "M_D_CPU0_SA_DQ<17>")
	)
	(arc
		(start 344.37066 -273.942556)
		(mid 344.183462 -273.892413)
		(end 343.996264 -273.942556)
		(width 0.088646)
		(layer "In11.Cu")
		(net "M_D_CPU0_SA_DQ<17>")
	)
	(arc
		(start 341.55126 -273.942556)
		(mid 341.364062 -273.892413)
		(end 341.176864 -273.942556)
		(width 0.088646)
		(layer "In11.Cu")
		(net "M_D_CPU0_SA_DQ<17>")
	)
	(arc
		(start 337.79206 -273.942556)
		(mid 337.604862 -273.892413)
		(end 337.417664 -273.942556)
		(width 0.088646)
		(layer "In11.Cu")
		(net "M_D_CPU0_SA_DQ<17>")
	)
	(arc
		(start 334.583532 -273.951192)
		(mid 334.307057 -274.018512)
		(end 334.03286 -273.942556)
		(width 0.088646)
		(layer "In11.Cu")
		(net "M_D_CPU0_SA_DQ<17>")
	)
	(arc
		(start 342.101932 -273.951192)
		(mid 341.825457 -274.018512)
		(end 341.55126 -273.942556)
		(width 0.088646)
		(layer "In11.Cu")
		(net "M_D_CPU0_SA_DQ<17>")
	)
	(arc
		(start 340.61146 -273.942556)
		(mid 340.424262 -273.892413)
		(end 340.237064 -273.942556)
		(width 0.088646)
		(layer "In11.Cu")
		(net "M_D_CPU0_SA_DQ<17>")
	)
	(arc
		(start 334.97266 -273.942556)
		(mid 334.785462 -273.892413)
		(end 334.598264 -273.942556)
		(width 0.088646)
		(layer "In11.Cu")
		(net "M_D_CPU0_SA_DQ<17>")
	)
	(arc
		(start 345.861132 -273.951192)
		(mid 345.584657 -274.018512)
		(end 345.31046 -273.942556)
		(width 0.088646)
		(layer "In11.Cu")
		(net "M_D_CPU0_SA_DQ<17>")
	)
	(arc
		(start 336.85226 -273.942556)
		(mid 336.665062 -273.892413)
		(end 336.477864 -273.942556)
		(width 0.088646)
		(layer "In11.Cu")
		(net "M_D_CPU0_SA_DQ<17>")
	)
	(arc
		(start 341.162132 -273.951192)
		(mid 340.885657 -274.018512)
		(end 340.61146 -273.942556)
		(width 0.088646)
		(layer "In11.Cu")
		(net "M_D_CPU0_SA_DQ<17>")
	)
	(arc
		(start 342.49106 -273.942556)
		(mid 342.303862 -273.892413)
		(end 342.116664 -273.942556)
		(width 0.088646)
		(layer "In11.Cu")
		(net "M_D_CPU0_SA_DQ<17>")
	)
	(arc
		(start 344.921332 -273.951192)
		(mid 344.644857 -274.018512)
		(end 344.37066 -273.942556)
		(width 0.088646)
		(layer "In11.Cu")
		(net "M_D_CPU0_SA_DQ<17>")
	)
	(arc
		(start 337.417664 -273.942556)
		(mid 337.134962 -274.018332)
		(end 336.85226 -273.942556)
		(width 0.088646)
		(layer "In11.Cu")
		(net "M_D_CPU0_SA_DQ<17>")
	)
	(arc
		(start 339.287104 -273.948652)
		(mid 339.008672 -274.018498)
		(end 338.73186 -273.942556)
		(width 0.088646)
		(layer "In11.Cu")
		(net "M_D_CPU0_SA_DQ<17>")
	)
	(arc
		(start 336.477864 -273.942556)
		(mid 336.195162 -274.018332)
		(end 335.91246 -273.942556)
		(width 0.088646)
		(layer "In11.Cu")
		(net "M_D_CPU0_SA_DQ<17>")
	)
	(arc
		(start 343.43086 -273.942556)
		(mid 343.243662 -273.892413)
		(end 343.056464 -273.942556)
		(width 0.088646)
		(layer "In11.Cu")
		(net "M_D_CPU0_SA_DQ<17>")
	)
	(arc
		(start 335.91246 -273.942556)
		(mid 335.725262 -273.892413)
		(end 335.538064 -273.942556)
		(width 0.088646)
		(layer "In11.Cu")
		(net "M_D_CPU0_SA_DQ<17>")
	)
	(arc
		(start 339.671914 -273.942556)
		(mid 339.484716 -273.892413)
		(end 339.297518 -273.942556)
		(width 0.088646)
		(layer "In11.Cu")
		(net "M_D_CPU0_SA_DQ<17>")
	)
	(arc
		(start 345.31046 -273.942556)
		(mid 345.123262 -273.892413)
		(end 344.936064 -273.942556)
		(width 0.088646)
		(layer "In11.Cu")
		(net "M_D_CPU0_SA_DQ<17>")
	)
	(segment
		(start 347.003116 -273.730974)
		(end 347.003116 -274.26666)
		(width 0.20066)
		(layer "F.Cu")
		(net "M_D_CPU0_SA_DQ<16>")
	)
	(segment
		(start 258.28498 -297.393106)
		(end 258.28498 -297.682666)
		(width 0.20066)
		(layer "F.Cu")
		(net "M_D_CPU0_SA_DQ<16>")
	)
	(segment
		(start 257.414776 -297.616626)
		(end 256.080514 -297.616626)
		(width 0.20066)
		(layer "F.Cu")
		(net "M_D_CPU0_SA_DQ<16>")
	)
	(segment
		(start 259.056378 -297.183556)
		(end 258.49453 -297.183556)
		(width 0.20066)
		(layer "F.Cu")
		(net "M_D_CPU0_SA_DQ<16>")
	)
	(segment
		(start 263.624314 -297.616626)
		(end 262.255254 -297.616626)
		(width 0.20066)
		(layer "F.Cu")
		(net "M_D_CPU0_SA_DQ<16>")
	)
	(segment
		(start 259.31241 -297.191684)
		(end 259.064506 -297.191684)
		(width 0.101854)
		(layer "F.Cu")
		(net "M_D_CPU0_SA_DQ<16>")
	)
	(segment
		(start 261.381494 -297.191684)
		(end 259.31241 -297.191684)
		(width 0.1016)
		(layer "F.Cu")
		(net "M_D_CPU0_SA_DQ<16>")
	)
	(segment
		(start 347.003116 -274.26666)
		(end 347.002862 -274.266914)
		(width 0.20066)
		(layer "F.Cu")
		(net "M_D_CPU0_SA_DQ<16>")
	)
	(segment
		(start 258.11226 -297.855386)
		(end 257.653536 -297.855386)
		(width 0.20066)
		(layer "F.Cu")
		(net "M_D_CPU0_SA_DQ<16>")
	)
	(segment
		(start 262.255254 -297.616626)
		(end 261.830312 -297.191684)
		(width 0.20066)
		(layer "F.Cu")
		(net "M_D_CPU0_SA_DQ<16>")
	)
	(segment
		(start 258.49453 -297.183556)
		(end 258.28498 -297.393106)
		(width 0.20066)
		(layer "F.Cu")
		(net "M_D_CPU0_SA_DQ<16>")
	)
	(segment
		(start 261.830312 -297.191684)
		(end 261.381494 -297.191684)
		(width 0.20066)
		(layer "F.Cu")
		(net "M_D_CPU0_SA_DQ<16>")
	)
	(segment
		(start 258.28498 -297.682666)
		(end 258.11226 -297.855386)
		(width 0.20066)
		(layer "F.Cu")
		(net "M_D_CPU0_SA_DQ<16>")
	)
	(segment
		(start 259.064506 -297.191684)
		(end 259.056378 -297.183556)
		(width 0.101854)
		(layer "F.Cu")
		(net "M_D_CPU0_SA_DQ<16>")
	)
	(segment
		(start 264.729214 -297.616626)
		(end 263.624314 -297.616626)
		(width 0.20066)
		(layer "F.Cu")
		(net "M_D_CPU0_SA_DQ<16>")
	)
	(segment
		(start 257.653536 -297.855386)
		(end 257.414776 -297.616626)
		(width 0.20066)
		(layer "F.Cu")
		(net "M_D_CPU0_SA_DQ<16>")
	)
	(segment
		(start 268.473936 -297.19397)
		(end 268.141704 -296.861738)
		(width 0.18288)
		(layer "In11.Cu")
		(net "M_D_CPU0_SA_DQ<16>")
	)
	(segment
		(start 310.506872 -294.711882)
		(end 310.306974 -294.591486)
		(width 0.18288)
		(layer "In11.Cu")
		(net "M_D_CPU0_SA_DQ<16>")
	)
	(segment
		(start 297.119294 -300.334426)
		(end 295.239694 -300.591728)
		(width 0.18288)
		(layer "In11.Cu")
		(net "M_D_CPU0_SA_DQ<16>")
	)
	(segment
		(start 302.157384 -298.067476)
		(end 300.737016 -299.487844)
		(width 0.18288)
		(layer "In11.Cu")
		(net "M_D_CPU0_SA_DQ<16>")
	)
	(segment
		(start 285.409894 -299.623226)
		(end 284.597094 -299.74159)
		(width 0.18288)
		(layer "In11.Cu")
		(net "M_D_CPU0_SA_DQ<16>")
	)
	(segment
		(start 271.185894 -297.964098)
		(end 270.452342 -297.877992)
		(width 0.18288)
		(layer "In11.Cu")
		(net "M_D_CPU0_SA_DQ<16>")
	)
	(segment
		(start 268.141704 -296.861738)
		(end 267.772896 -296.861738)
		(width 0.18288)
		(layer "In11.Cu")
		(net "M_D_CPU0_SA_DQ<16>")
	)
	(segment
		(start 330.974446 -277.96871)
		(end 330.60767 -277.96871)
		(width 0.088646)
		(layer "In11.Cu")
		(net "M_D_CPU0_SA_DQ<16>")
	)
	(segment
		(start 294.630094 -300.591728)
		(end 293.812722 -300.715426)
		(width 0.18288)
		(layer "In11.Cu")
		(net "M_D_CPU0_SA_DQ<16>")
	)
	(segment
		(start 308.555136 -294.81272)
		(end 308.40426 -295.276016)
		(width 0.18288)
		(layer "In11.Cu")
		(net "M_D_CPU0_SA_DQ<16>")
	)
	(segment
		(start 270.452342 -297.877992)
		(end 269.780512 -297.877992)
		(width 0.18288)
		(layer "In11.Cu")
		(net "M_D_CPU0_SA_DQ<16>")
	)
	(segment
		(start 293.812722 -300.715426)
		(end 292.596824 -300.715426)
		(width 0.18288)
		(layer "In11.Cu")
		(net "M_D_CPU0_SA_DQ<16>")
	)
	(segment
		(start 340.151974 -274.762468)
		(end 340.14156 -274.756372)
		(width 0.088646)
		(layer "In11.Cu")
		(net "M_D_CPU0_SA_DQ<16>")
	)
	(segment
		(start 312.200544 -294.711882)
		(end 310.506872 -294.711882)
		(width 0.18288)
		(layer "In11.Cu")
		(net "M_D_CPU0_SA_DQ<16>")
	)
	(segment
		(start 304.89779 -296.790618)
		(end 303.491646 -297.500802)
		(width 0.18288)
		(layer "In11.Cu")
		(net "M_D_CPU0_SA_DQ<16>")
	)
	(segment
		(start 339.767164 -274.756372)
		(end 339.75675 -274.762468)
		(width 0.088646)
		(layer "In11.Cu")
		(net "M_D_CPU0_SA_DQ<16>")
	)
	(segment
		(start 299.51553 -299.74159)
		(end 298.770294 -299.74159)
		(width 0.18288)
		(layer "In11.Cu")
		(net "M_D_CPU0_SA_DQ<16>")
	)
	(segment
		(start 265.35507 -298.242482)
		(end 264.729214 -297.616626)
		(width 0.18288)
		(layer "In11.Cu")
		(net "M_D_CPU0_SA_DQ<16>")
	)
	(segment
		(start 277.788878 -300.602396)
		(end 277.42769 -300.602396)
		(width 0.18288)
		(layer "In11.Cu")
		(net "M_D_CPU0_SA_DQ<16>")
	)
	(segment
		(start 277.42769 -300.602396)
		(end 276.613112 -300.468792)
		(width 0.18288)
		(layer "In11.Cu")
		(net "M_D_CPU0_SA_DQ<16>")
	)
	(segment
		(start 342.975946 -274.765008)
		(end 342.961214 -274.756372)
		(width 0.088646)
		(layer "In11.Cu")
		(net "M_D_CPU0_SA_DQ<16>")
	)
	(segment
		(start 276.613112 -300.468792)
		(end 275.643848 -300.10862)
		(width 0.18288)
		(layer "In11.Cu")
		(net "M_D_CPU0_SA_DQ<16>")
	)
	(segment
		(start 280.202894 -300.591728)
		(end 277.799546 -300.591728)
		(width 0.18288)
		(layer "In11.Cu")
		(net "M_D_CPU0_SA_DQ<16>")
	)
	(segment
		(start 309.33644 -294.802306)
		(end 308.873144 -294.650922)
		(width 0.18288)
		(layer "In11.Cu")
		(net "M_D_CPU0_SA_DQ<16>")
	)
	(segment
		(start 295.239694 -300.591728)
		(end 294.630094 -300.591728)
		(width 0.18288)
		(layer "In11.Cu")
		(net "M_D_CPU0_SA_DQ<16>")
	)
	(segment
		(start 335.06791 -274.756372)
		(end 335.053178 -274.765008)
		(width 0.088646)
		(layer "In11.Cu")
		(net "M_D_CPU0_SA_DQ<16>")
	)
	(segment
		(start 288.021014 -299.776388)
		(end 287.340294 -299.623226)
		(width 0.18288)
		(layer "In11.Cu")
		(net "M_D_CPU0_SA_DQ<16>")
	)
	(segment
		(start 342.036146 -274.765008)
		(end 342.021414 -274.756372)
		(width 0.088646)
		(layer "In11.Cu")
		(net "M_D_CPU0_SA_DQ<16>")
	)
	(segment
		(start 316.996826 -290.590224)
		(end 316.996826 -291.16401)
		(width 0.18288)
		(layer "In11.Cu")
		(net "M_D_CPU0_SA_DQ<16>")
	)
	(segment
		(start 267.173202 -298.242482)
		(end 265.35507 -298.242482)
		(width 0.18288)
		(layer "In11.Cu")
		(net "M_D_CPU0_SA_DQ<16>")
	)
	(segment
		(start 310.306974 -294.591486)
		(end 309.750714 -294.591486)
		(width 0.18288)
		(layer "In11.Cu")
		(net "M_D_CPU0_SA_DQ<16>")
	)
	(segment
		(start 300.387004 -299.623226)
		(end 300.007274 -299.623226)
		(width 0.18288)
		(layer "In11.Cu")
		(net "M_D_CPU0_SA_DQ<16>")
	)
	(segment
		(start 267.579856 -297.054778)
		(end 267.579856 -297.835828)
		(width 0.18288)
		(layer "In11.Cu")
		(net "M_D_CPU0_SA_DQ<16>")
	)
	(segment
		(start 333.022702 -274.705572)
		(end 332.795118 -274.933156)
		(width 0.088646)
		(layer "In11.Cu")
		(net "M_D_CPU0_SA_DQ<16>")
	)
	(segment
		(start 313.042808 -294.137588)
		(end 312.657998 -294.522398)
		(width 0.18288)
		(layer "In11.Cu")
		(net "M_D_CPU0_SA_DQ<16>")
	)
	(segment
		(start 303.024286 -297.80484)
		(end 302.157384 -298.067476)
		(width 0.18288)
		(layer "In11.Cu")
		(net "M_D_CPU0_SA_DQ<16>")
	)
	(segment
		(start 306.835048 -295.47566)
		(end 306.212748 -295.47566)
		(width 0.18288)
		(layer "In11.Cu")
		(net "M_D_CPU0_SA_DQ<16>")
	)
	(segment
		(start 330.60767 -277.96871)
		(end 329.61834 -277.96871)
		(width 0.18288)
		(layer "In11.Cu")
		(net "M_D_CPU0_SA_DQ<16>")
	)
	(segment
		(start 341.096346 -274.765008)
		(end 341.081614 -274.756372)
		(width 0.088646)
		(layer "In11.Cu")
		(net "M_D_CPU0_SA_DQ<16>")
	)
	(segment
		(start 345.791028 -274.762468)
		(end 345.780614 -274.756372)
		(width 0.088646)
		(layer "In11.Cu")
		(net "M_D_CPU0_SA_DQ<16>")
	)
	(segment
		(start 269.09649 -297.19397)
		(end 268.473936 -297.19397)
		(width 0.18288)
		(layer "In11.Cu")
		(net "M_D_CPU0_SA_DQ<16>")
	)
	(segment
		(start 269.780512 -297.877992)
		(end 269.09649 -297.19397)
		(width 0.18288)
		(layer "In11.Cu")
		(net "M_D_CPU0_SA_DQ<16>")
	)
	(segment
		(start 274.455636 -298.920408)
		(end 272.245836 -297.964098)
		(width 0.18288)
		(layer "In11.Cu")
		(net "M_D_CPU0_SA_DQ<16>")
	)
	(segment
		(start 292.596824 -300.715426)
		(end 291.944552 -300.538388)
		(width 0.18288)
		(layer "In11.Cu")
		(net "M_D_CPU0_SA_DQ<16>")
	)
	(segment
		(start 281.290776 -300.436534)
		(end 280.202894 -300.591728)
		(width 0.18288)
		(layer "In11.Cu")
		(net "M_D_CPU0_SA_DQ<16>")
	)
	(segment
		(start 284.597094 -299.74159)
		(end 283.677614 -299.74159)
		(width 0.18288)
		(layer "In11.Cu")
		(net "M_D_CPU0_SA_DQ<16>")
	)
	(segment
		(start 346.423996 -274.71116)
		(end 346.345764 -274.756372)
		(width 0.088646)
		(layer "In11.Cu")
		(net "M_D_CPU0_SA_DQ<16>")
	)
	(segment
		(start 334.12811 -274.756372)
		(end 334.113378 -274.765008)
		(width 0.088646)
		(layer "In11.Cu")
		(net "M_D_CPU0_SA_DQ<16>")
	)
	(segment
		(start 267.772896 -296.861738)
		(end 267.579856 -297.054778)
		(width 0.18288)
		(layer "In11.Cu")
		(net "M_D_CPU0_SA_DQ<16>")
	)
	(segment
		(start 275.643848 -300.10862)
		(end 274.455636 -298.920408)
		(width 0.18288)
		(layer "In11.Cu")
		(net "M_D_CPU0_SA_DQ<16>")
	)
	(segment
		(start 267.579856 -297.835828)
		(end 267.173202 -298.242482)
		(width 0.18288)
		(layer "In11.Cu")
		(net "M_D_CPU0_SA_DQ<16>")
	)
	(segment
		(start 277.799546 -300.591728)
		(end 277.788878 -300.602396)
		(width 0.18288)
		(layer "In11.Cu")
		(net "M_D_CPU0_SA_DQ<16>")
	)
	(segment
		(start 344.855546 -274.765008)
		(end 344.840814 -274.756372)
		(width 0.088646)
		(layer "In11.Cu")
		(net "M_D_CPU0_SA_DQ<16>")
	)
	(segment
		(start 332.795118 -277.149052)
		(end 331.790802 -278.153368)
		(width 0.088646)
		(layer "In11.Cu")
		(net "M_D_CPU0_SA_DQ<16>")
	)
	(segment
		(start 283.677614 -299.74159)
		(end 282.415742 -300.34992)
		(width 0.18288)
		(layer "In11.Cu")
		(net "M_D_CPU0_SA_DQ<16>")
	)
	(segment
		(start 308.40426 -295.276016)
		(end 307.937154 -295.513506)
		(width 0.18288)
		(layer "In11.Cu")
		(net "M_D_CPU0_SA_DQ<16>")
	)
	(segment
		(start 287.340294 -299.623226)
		(end 285.409894 -299.623226)
		(width 0.18288)
		(layer "In11.Cu")
		(net "M_D_CPU0_SA_DQ<16>")
	)
	(segment
		(start 306.872894 -295.513506)
		(end 306.835048 -295.47566)
		(width 0.18288)
		(layer "In11.Cu")
		(net "M_D_CPU0_SA_DQ<16>")
	)
	(segment
		(start 303.491646 -297.500802)
		(end 303.024286 -297.80484)
		(width 0.18288)
		(layer "In11.Cu")
		(net "M_D_CPU0_SA_DQ<16>")
	)
	(segment
		(start 308.873144 -294.650922)
		(end 308.555136 -294.81272)
		(width 0.18288)
		(layer "In11.Cu")
		(net "M_D_CPU0_SA_DQ<16>")
	)
	(segment
		(start 291.944552 -300.538388)
		(end 290.972494 -300.309026)
		(width 0.18288)
		(layer "In11.Cu")
		(net "M_D_CPU0_SA_DQ<16>")
	)
	(segment
		(start 300.737016 -299.487844)
		(end 300.387004 -299.623226)
		(width 0.18288)
		(layer "In11.Cu")
		(net "M_D_CPU0_SA_DQ<16>")
	)
	(segment
		(start 307.937154 -295.513506)
		(end 306.872894 -295.513506)
		(width 0.18288)
		(layer "In11.Cu")
		(net "M_D_CPU0_SA_DQ<16>")
	)
	(segment
		(start 331.790802 -278.153368)
		(end 331.159104 -278.153368)
		(width 0.088646)
		(layer "In11.Cu")
		(net "M_D_CPU0_SA_DQ<16>")
	)
	(segment
		(start 300.007274 -299.623226)
		(end 299.51553 -299.74159)
		(width 0.18288)
		(layer "In11.Cu")
		(net "M_D_CPU0_SA_DQ<16>")
	)
	(segment
		(start 290.972494 -300.309026)
		(end 288.021014 -299.776388)
		(width 0.18288)
		(layer "In11.Cu")
		(net "M_D_CPU0_SA_DQ<16>")
	)
	(segment
		(start 332.795118 -274.933156)
		(end 332.795118 -277.149052)
		(width 0.088646)
		(layer "In11.Cu")
		(net "M_D_CPU0_SA_DQ<16>")
	)
	(segment
		(start 331.159104 -278.153368)
		(end 330.974446 -277.96871)
		(width 0.088646)
		(layer "In11.Cu")
		(net "M_D_CPU0_SA_DQ<16>")
	)
	(segment
		(start 343.915746 -274.765008)
		(end 343.901014 -274.756372)
		(width 0.088646)
		(layer "In11.Cu")
		(net "M_D_CPU0_SA_DQ<16>")
	)
	(segment
		(start 316.996826 -291.16401)
		(end 314.717176 -293.44366)
		(width 0.18288)
		(layer "In11.Cu")
		(net "M_D_CPU0_SA_DQ<16>")
	)
	(segment
		(start 272.245836 -297.964098)
		(end 271.185894 -297.964098)
		(width 0.18288)
		(layer "In11.Cu")
		(net "M_D_CPU0_SA_DQ<16>")
	)
	(segment
		(start 312.657998 -294.522398)
		(end 312.200544 -294.711882)
		(width 0.18288)
		(layer "In11.Cu")
		(net "M_D_CPU0_SA_DQ<16>")
	)
	(segment
		(start 329.61834 -277.96871)
		(end 316.996826 -290.590224)
		(width 0.18288)
		(layer "In11.Cu")
		(net "M_D_CPU0_SA_DQ<16>")
	)
	(segment
		(start 298.770294 -299.74159)
		(end 297.119294 -300.334426)
		(width 0.18288)
		(layer "In11.Cu")
		(net "M_D_CPU0_SA_DQ<16>")
	)
	(segment
		(start 336.007964 -274.756372)
		(end 335.99755 -274.762468)
		(width 0.088646)
		(layer "In11.Cu")
		(net "M_D_CPU0_SA_DQ<16>")
	)
	(segment
		(start 309.750714 -294.591486)
		(end 309.33644 -294.802306)
		(width 0.18288)
		(layer "In11.Cu")
		(net "M_D_CPU0_SA_DQ<16>")
	)
	(segment
		(start 306.212748 -295.47566)
		(end 304.89779 -296.790618)
		(width 0.18288)
		(layer "In11.Cu")
		(net "M_D_CPU0_SA_DQ<16>")
	)
	(segment
		(start 338.272374 -274.762468)
		(end 338.26196 -274.756372)
		(width 0.088646)
		(layer "In11.Cu")
		(net "M_D_CPU0_SA_DQ<16>")
	)
	(segment
		(start 333.375508 -274.705572)
		(end 333.022702 -274.705572)
		(width 0.088646)
		(layer "In11.Cu")
		(net "M_D_CPU0_SA_DQ<16>")
	)
	(segment
		(start 314.717176 -293.44366)
		(end 313.042808 -294.137588)
		(width 0.18288)
		(layer "In11.Cu")
		(net "M_D_CPU0_SA_DQ<16>")
	)
	(segment
		(start 282.415742 -300.34992)
		(end 281.290776 -300.436534)
		(width 0.18288)
		(layer "In11.Cu")
		(net "M_D_CPU0_SA_DQ<16>")
	)
	(arc
		(start 343.901014 -274.756372)
		(mid 343.713816 -274.706229)
		(end 343.526618 -274.756372)
		(width 0.088646)
		(layer "In11.Cu")
		(net "M_D_CPU0_SA_DQ<16>")
	)
	(arc
		(start 337.32216 -274.756372)
		(mid 337.134962 -274.706229)
		(end 336.947764 -274.756372)
		(width 0.088646)
		(layer "In11.Cu")
		(net "M_D_CPU0_SA_DQ<16>")
	)
	(arc
		(start 347.002862 -274.266914)
		(mid 346.727969 -274.507982)
		(end 346.423996 -274.71116)
		(width 0.088646)
		(layer "In11.Cu")
		(net "M_D_CPU0_SA_DQ<16>")
	)
	(arc
		(start 346.345764 -274.756372)
		(mid 346.069205 -274.832115)
		(end 345.791028 -274.762468)
		(width 0.088646)
		(layer "In11.Cu")
		(net "M_D_CPU0_SA_DQ<16>")
	)
	(arc
		(start 341.647018 -274.756372)
		(mid 341.372819 -274.832207)
		(end 341.096346 -274.765008)
		(width 0.088646)
		(layer "In11.Cu")
		(net "M_D_CPU0_SA_DQ<16>")
	)
	(arc
		(start 337.887564 -274.756372)
		(mid 337.604862 -274.832148)
		(end 337.32216 -274.756372)
		(width 0.088646)
		(layer "In11.Cu")
		(net "M_D_CPU0_SA_DQ<16>")
	)
	(arc
		(start 338.26196 -274.756372)
		(mid 338.074762 -274.706229)
		(end 337.887564 -274.756372)
		(width 0.088646)
		(layer "In11.Cu")
		(net "M_D_CPU0_SA_DQ<16>")
	)
	(arc
		(start 335.99755 -274.762468)
		(mid 335.719118 -274.832314)
		(end 335.442306 -274.756372)
		(width 0.088646)
		(layer "In11.Cu")
		(net "M_D_CPU0_SA_DQ<16>")
	)
	(arc
		(start 334.113378 -274.765008)
		(mid 333.836903 -274.832328)
		(end 333.562706 -274.756372)
		(width 0.088646)
		(layer "In11.Cu")
		(net "M_D_CPU0_SA_DQ<16>")
	)
	(arc
		(start 344.840814 -274.756372)
		(mid 344.653616 -274.706229)
		(end 344.466418 -274.756372)
		(width 0.088646)
		(layer "In11.Cu")
		(net "M_D_CPU0_SA_DQ<16>")
	)
	(arc
		(start 340.14156 -274.756372)
		(mid 339.954362 -274.706229)
		(end 339.767164 -274.756372)
		(width 0.088646)
		(layer "In11.Cu")
		(net "M_D_CPU0_SA_DQ<16>")
	)
	(arc
		(start 334.502506 -274.756372)
		(mid 334.315308 -274.706229)
		(end 334.12811 -274.756372)
		(width 0.088646)
		(layer "In11.Cu")
		(net "M_D_CPU0_SA_DQ<16>")
	)
	(arc
		(start 336.38236 -274.756372)
		(mid 336.195162 -274.706229)
		(end 336.007964 -274.756372)
		(width 0.088646)
		(layer "In11.Cu")
		(net "M_D_CPU0_SA_DQ<16>")
	)
	(arc
		(start 345.780614 -274.756372)
		(mid 345.593416 -274.706229)
		(end 345.406218 -274.756372)
		(width 0.088646)
		(layer "In11.Cu")
		(net "M_D_CPU0_SA_DQ<16>")
	)
	(arc
		(start 338.827618 -274.756372)
		(mid 338.550805 -274.832242)
		(end 338.272374 -274.762468)
		(width 0.088646)
		(layer "In11.Cu")
		(net "M_D_CPU0_SA_DQ<16>")
	)
	(arc
		(start 342.586818 -274.756372)
		(mid 342.312619 -274.832207)
		(end 342.036146 -274.765008)
		(width 0.088646)
		(layer "In11.Cu")
		(net "M_D_CPU0_SA_DQ<16>")
	)
	(arc
		(start 335.442306 -274.756372)
		(mid 335.255108 -274.706229)
		(end 335.06791 -274.756372)
		(width 0.088646)
		(layer "In11.Cu")
		(net "M_D_CPU0_SA_DQ<16>")
	)
	(arc
		(start 339.202014 -274.756372)
		(mid 339.014816 -274.706229)
		(end 338.827618 -274.756372)
		(width 0.088646)
		(layer "In11.Cu")
		(net "M_D_CPU0_SA_DQ<16>")
	)
	(arc
		(start 336.947764 -274.756372)
		(mid 336.665062 -274.832148)
		(end 336.38236 -274.756372)
		(width 0.088646)
		(layer "In11.Cu")
		(net "M_D_CPU0_SA_DQ<16>")
	)
	(arc
		(start 344.466418 -274.756372)
		(mid 344.192219 -274.832207)
		(end 343.915746 -274.765008)
		(width 0.088646)
		(layer "In11.Cu")
		(net "M_D_CPU0_SA_DQ<16>")
	)
	(arc
		(start 342.021414 -274.756372)
		(mid 341.834216 -274.706229)
		(end 341.647018 -274.756372)
		(width 0.088646)
		(layer "In11.Cu")
		(net "M_D_CPU0_SA_DQ<16>")
	)
	(arc
		(start 339.75675 -274.762468)
		(mid 339.478572 -274.832191)
		(end 339.202014 -274.756372)
		(width 0.088646)
		(layer "In11.Cu")
		(net "M_D_CPU0_SA_DQ<16>")
	)
	(arc
		(start 341.081614 -274.756372)
		(mid 340.894416 -274.706229)
		(end 340.707218 -274.756372)
		(width 0.088646)
		(layer "In11.Cu")
		(net "M_D_CPU0_SA_DQ<16>")
	)
	(arc
		(start 345.406218 -274.756372)
		(mid 345.132019 -274.832207)
		(end 344.855546 -274.765008)
		(width 0.088646)
		(layer "In11.Cu")
		(net "M_D_CPU0_SA_DQ<16>")
	)
	(arc
		(start 335.053178 -274.765008)
		(mid 334.776703 -274.832328)
		(end 334.502506 -274.756372)
		(width 0.088646)
		(layer "In11.Cu")
		(net "M_D_CPU0_SA_DQ<16>")
	)
	(arc
		(start 343.526618 -274.756372)
		(mid 343.252419 -274.832207)
		(end 342.975946 -274.765008)
		(width 0.088646)
		(layer "In11.Cu")
		(net "M_D_CPU0_SA_DQ<16>")
	)
	(arc
		(start 333.562706 -274.756372)
		(mid 333.47245 -274.71865)
		(end 333.375508 -274.705572)
		(width 0.088646)
		(layer "In11.Cu")
		(net "M_D_CPU0_SA_DQ<16>")
	)
	(arc
		(start 340.707218 -274.756372)
		(mid 340.430405 -274.832242)
		(end 340.151974 -274.762468)
		(width 0.088646)
		(layer "In11.Cu")
		(net "M_D_CPU0_SA_DQ<16>")
	)
	(arc
		(start 342.961214 -274.756372)
		(mid 342.774016 -274.706229)
		(end 342.586818 -274.756372)
		(width 0.088646)
		(layer "In11.Cu")
		(net "M_D_CPU0_SA_DQ<16>")
	)
	(segment
		(start 264.825226 -298.891706)
		(end 262.752332 -298.891706)
		(width 0.1016)
		(layer "F.Cu")
		(net "M_D_CPU0_SA_DQ<15>")
	)
	(segment
		(start 262.146288 -298.90593)
		(end 262.003794 -298.763436)
		(width 0.20066)
		(layer "F.Cu")
		(net "M_D_CPU0_SA_DQ<15>")
	)
	(segment
		(start 267.724382 -298.466764)
		(end 266.90828 -298.466764)
		(width 0.20066)
		(layer "F.Cu")
		(net "M_D_CPU0_SA_DQ<15>")
	)
	(segment
		(start 262.50011 -298.90593)
		(end 262.146288 -298.90593)
		(width 0.20066)
		(layer "F.Cu")
		(net "M_D_CPU0_SA_DQ<15>")
	)
	(segment
		(start 268.829282 -298.466764)
		(end 267.724382 -298.466764)
		(width 0.20066)
		(layer "F.Cu")
		(net "M_D_CPU0_SA_DQ<15>")
	)
	(segment
		(start 266.700762 -298.674282)
		(end 266.25423 -298.674282)
		(width 0.20066)
		(layer "F.Cu")
		(net "M_D_CPU0_SA_DQ<15>")
	)
	(segment
		(start 262.752332 -298.891706)
		(end 262.514334 -298.891706)
		(width 0.101854)
		(layer "F.Cu")
		(net "M_D_CPU0_SA_DQ<15>")
	)
	(segment
		(start 265.64717 -298.462446)
		(end 265.518646 -298.59097)
		(width 0.20066)
		(layer "F.Cu")
		(net "M_D_CPU0_SA_DQ<15>")
	)
	(segment
		(start 266.042394 -298.462446)
		(end 265.64717 -298.462446)
		(width 0.20066)
		(layer "F.Cu")
		(net "M_D_CPU0_SA_DQ<15>")
	)
	(segment
		(start 265.518646 -298.742608)
		(end 265.369548 -298.891706)
		(width 0.20066)
		(layer "F.Cu")
		(net "M_D_CPU0_SA_DQ<15>")
	)
	(segment
		(start 266.90828 -298.466764)
		(end 266.700762 -298.674282)
		(width 0.20066)
		(layer "F.Cu")
		(net "M_D_CPU0_SA_DQ<15>")
	)
	(segment
		(start 266.25423 -298.674282)
		(end 266.042394 -298.462446)
		(width 0.20066)
		(layer "F.Cu")
		(net "M_D_CPU0_SA_DQ<15>")
	)
	(segment
		(start 265.518646 -298.59097)
		(end 265.518646 -298.742608)
		(width 0.20066)
		(layer "F.Cu")
		(net "M_D_CPU0_SA_DQ<15>")
	)
	(segment
		(start 262.514334 -298.891706)
		(end 262.50011 -298.90593)
		(width 0.101854)
		(layer "F.Cu")
		(net "M_D_CPU0_SA_DQ<15>")
	)
	(segment
		(start 262.003794 -298.763436)
		(end 262.003794 -298.592748)
		(width 0.20066)
		(layer "F.Cu")
		(net "M_D_CPU0_SA_DQ<15>")
	)
	(segment
		(start 262.003794 -298.592748)
		(end 261.87781 -298.466764)
		(width 0.20066)
		(layer "F.Cu")
		(net "M_D_CPU0_SA_DQ<15>")
	)
	(segment
		(start 265.369548 -298.891706)
		(end 264.825226 -298.891706)
		(width 0.20066)
		(layer "F.Cu")
		(net "M_D_CPU0_SA_DQ<15>")
	)
	(segment
		(start 261.87781 -298.466764)
		(end 260.180582 -298.466764)
		(width 0.20066)
		(layer "F.Cu")
		(net "M_D_CPU0_SA_DQ<15>")
	)
	(arc
		(start 347.942916 -275.35886)
		(mid 347.942852 -275.62683)
		(end 347.942662 -275.8948)
		(width 0.20066)
		(layer "F.Cu")
		(net "M_D_CPU0_SA_DQ<15>")
	)
	(segment
		(start 306.384706 -297.136566)
		(end 305.160426 -298.360846)
		(width 0.18288)
		(layer "In11.Cu")
		(net "M_D_CPU0_SA_DQ<15>")
	)
	(segment
		(start 299.405294 -303.142142)
		(end 298.151042 -303.142142)
		(width 0.18288)
		(layer "In11.Cu")
		(net "M_D_CPU0_SA_DQ<15>")
	)
	(segment
		(start 344.855546 -275.396452)
		(end 344.840814 -275.405088)
		(width 0.088646)
		(layer "In11.Cu")
		(net "M_D_CPU0_SA_DQ<15>")
	)
	(segment
		(start 294.07739 -302.710342)
		(end 293.303198 -302.710342)
		(width 0.18288)
		(layer "In11.Cu")
		(net "M_D_CPU0_SA_DQ<15>")
	)
	(segment
		(start 287.429702 -302.710342)
		(end 287.236662 -302.903382)
		(width 0.18288)
		(layer "In11.Cu")
		(net "M_D_CPU0_SA_DQ<15>")
	)
	(segment
		(start 284.940502 -302.710342)
		(end 284.634686 -302.710342)
		(width 0.18288)
		(layer "In11.Cu")
		(net "M_D_CPU0_SA_DQ<15>")
	)
	(segment
		(start 292.216078 -302.710342)
		(end 290.794694 -302.710342)
		(width 0.18288)
		(layer "In11.Cu")
		(net "M_D_CPU0_SA_DQ<15>")
	)
	(segment
		(start 304.604674 -298.360846)
		(end 303.951894 -299.013626)
		(width 0.18288)
		(layer "In11.Cu")
		(net "M_D_CPU0_SA_DQ<15>")
	)
	(segment
		(start 313.482228 -295.419272)
		(end 312.417714 -296.483786)
		(width 0.18288)
		(layer "In11.Cu")
		(net "M_D_CPU0_SA_DQ<15>")
	)
	(segment
		(start 288.445702 -303.276508)
		(end 288.130742 -303.276508)
		(width 0.18288)
		(layer "In11.Cu")
		(net "M_D_CPU0_SA_DQ<15>")
	)
	(segment
		(start 297.248326 -303.304702)
		(end 297.04665 -303.103026)
		(width 0.18288)
		(layer "In11.Cu")
		(net "M_D_CPU0_SA_DQ<15>")
	)
	(segment
		(start 342.975946 -275.396452)
		(end 342.961214 -275.405088)
		(width 0.088646)
		(layer "In11.Cu")
		(net "M_D_CPU0_SA_DQ<15>")
	)
	(segment
		(start 340.151974 -275.398992)
		(end 340.14156 -275.405088)
		(width 0.088646)
		(layer "In11.Cu")
		(net "M_D_CPU0_SA_DQ<15>")
	)
	(segment
		(start 290.601654 -302.903382)
		(end 290.601654 -303.36998)
		(width 0.18288)
		(layer "In11.Cu")
		(net "M_D_CPU0_SA_DQ<15>")
	)
	(segment
		(start 333.6544 -276.244558)
		(end 333.44485 -276.244558)
		(width 0.088646)
		(layer "In11.Cu")
		(net "M_D_CPU0_SA_DQ<15>")
	)
	(segment
		(start 343.915746 -275.396452)
		(end 343.901014 -275.405088)
		(width 0.088646)
		(layer "In11.Cu")
		(net "M_D_CPU0_SA_DQ<15>")
	)
	(segment
		(start 309.120794 -296.130726)
		(end 307.873654 -297.377866)
		(width 0.18288)
		(layer "In11.Cu")
		(net "M_D_CPU0_SA_DQ<15>")
	)
	(segment
		(start 311.041034 -296.483786)
		(end 310.687974 -296.130726)
		(width 0.18288)
		(layer "In11.Cu")
		(net "M_D_CPU0_SA_DQ<15>")
	)
	(segment
		(start 303.951894 -299.013626)
		(end 302.935894 -299.013626)
		(width 0.18288)
		(layer "In11.Cu")
		(net "M_D_CPU0_SA_DQ<15>")
	)
	(segment
		(start 290.408614 -303.56302)
		(end 290.093654 -303.56302)
		(width 0.18288)
		(layer "In11.Cu")
		(net "M_D_CPU0_SA_DQ<15>")
	)
	(segment
		(start 280.253694 -303.992026)
		(end 279.308052 -303.992026)
		(width 0.18288)
		(layer "In11.Cu")
		(net "M_D_CPU0_SA_DQ<15>")
	)
	(segment
		(start 272.158968 -299.085)
		(end 269.447518 -299.085)
		(width 0.18288)
		(layer "In11.Cu")
		(net "M_D_CPU0_SA_DQ<15>")
	)
	(segment
		(start 287.236662 -303.083468)
		(end 287.043622 -303.276508)
		(width 0.18288)
		(layer "In11.Cu")
		(net "M_D_CPU0_SA_DQ<15>")
	)
	(segment
		(start 285.834582 -303.083468)
		(end 285.641542 -303.276508)
		(width 0.18288)
		(layer "In11.Cu")
		(net "M_D_CPU0_SA_DQ<15>")
	)
	(segment
		(start 347.629988 -275.8948)
		(end 347.56471 -275.829522)
		(width 0.088646)
		(layer "In11.Cu")
		(net "M_D_CPU0_SA_DQ<15>")
	)
	(segment
		(start 290.794694 -302.710342)
		(end 290.601654 -302.903382)
		(width 0.18288)
		(layer "In11.Cu")
		(net "M_D_CPU0_SA_DQ<15>")
	)
	(segment
		(start 288.130742 -303.276508)
		(end 287.937702 -303.083468)
		(width 0.18288)
		(layer "In11.Cu")
		(net "M_D_CPU0_SA_DQ<15>")
	)
	(segment
		(start 293.110158 -303.239678)
		(end 292.917118 -303.432718)
		(width 0.18288)
		(layer "In11.Cu")
		(net "M_D_CPU0_SA_DQ<15>")
	)
	(segment
		(start 285.641542 -303.276508)
		(end 285.326582 -303.276508)
		(width 0.18288)
		(layer "In11.Cu")
		(net "M_D_CPU0_SA_DQ<15>")
	)
	(segment
		(start 269.447518 -299.085)
		(end 268.829282 -298.466764)
		(width 0.18288)
		(layer "In11.Cu")
		(net "M_D_CPU0_SA_DQ<15>")
	)
	(segment
		(start 280.456894 -303.280826)
		(end 280.456894 -303.788826)
		(width 0.18288)
		(layer "In11.Cu")
		(net "M_D_CPU0_SA_DQ<15>")
	)
	(segment
		(start 332.98765 -277.236682)
		(end 331.612494 -278.611838)
		(width 0.088646)
		(layer "In11.Cu")
		(net "M_D_CPU0_SA_DQ<15>")
	)
	(segment
		(start 292.917118 -303.432718)
		(end 292.602158 -303.432718)
		(width 0.18288)
		(layer "In11.Cu")
		(net "M_D_CPU0_SA_DQ<15>")
	)
	(segment
		(start 287.236662 -302.903382)
		(end 287.236662 -303.083468)
		(width 0.18288)
		(layer "In11.Cu")
		(net "M_D_CPU0_SA_DQ<15>")
	)
	(segment
		(start 292.409118 -302.903382)
		(end 292.216078 -302.710342)
		(width 0.18288)
		(layer "In11.Cu")
		(net "M_D_CPU0_SA_DQ<15>")
	)
	(segment
		(start 290.601654 -303.36998)
		(end 290.408614 -303.56302)
		(width 0.18288)
		(layer "In11.Cu")
		(net "M_D_CPU0_SA_DQ<15>")
	)
	(segment
		(start 274.804378 -300.461426)
		(end 273.535394 -300.461426)
		(width 0.18288)
		(layer "In11.Cu")
		(net "M_D_CPU0_SA_DQ<15>")
	)
	(segment
		(start 285.133542 -302.903382)
		(end 284.940502 -302.710342)
		(width 0.18288)
		(layer "In11.Cu")
		(net "M_D_CPU0_SA_DQ<15>")
	)
	(segment
		(start 286.535622 -303.083468)
		(end 286.535622 -302.52162)
		(width 0.18288)
		(layer "In11.Cu")
		(net "M_D_CPU0_SA_DQ<15>")
	)
	(segment
		(start 330.817474 -278.77135)
		(end 329.950826 -278.77135)
		(width 0.18288)
		(layer "In11.Cu")
		(net "M_D_CPU0_SA_DQ<15>")
	)
	(segment
		(start 287.043622 -303.276508)
		(end 286.728662 -303.276508)
		(width 0.18288)
		(layer "In11.Cu")
		(net "M_D_CPU0_SA_DQ<15>")
	)
	(segment
		(start 329.950826 -278.77135)
		(end 317.799466 -290.92271)
		(width 0.18288)
		(layer "In11.Cu")
		(net "M_D_CPU0_SA_DQ<15>")
	)
	(segment
		(start 294.510714 -303.992026)
		(end 294.381174 -303.862486)
		(width 0.18288)
		(layer "In11.Cu")
		(net "M_D_CPU0_SA_DQ<15>")
	)
	(segment
		(start 294.381174 -303.014126)
		(end 294.07739 -302.710342)
		(width 0.18288)
		(layer "In11.Cu")
		(net "M_D_CPU0_SA_DQ<15>")
	)
	(segment
		(start 305.160426 -298.360846)
		(end 304.604674 -298.360846)
		(width 0.18288)
		(layer "In11.Cu")
		(net "M_D_CPU0_SA_DQ<15>")
	)
	(segment
		(start 289.900614 -302.903382)
		(end 289.707574 -302.710342)
		(width 0.18288)
		(layer "In11.Cu")
		(net "M_D_CPU0_SA_DQ<15>")
	)
	(segment
		(start 295.137586 -303.992026)
		(end 294.510714 -303.992026)
		(width 0.18288)
		(layer "In11.Cu")
		(net "M_D_CPU0_SA_DQ<15>")
	)
	(segment
		(start 302.935894 -299.013626)
		(end 300.910244 -301.039276)
		(width 0.18288)
		(layer "In11.Cu")
		(net "M_D_CPU0_SA_DQ<15>")
	)
	(segment
		(start 286.728662 -303.276508)
		(end 286.535622 -303.083468)
		(width 0.18288)
		(layer "In11.Cu")
		(net "M_D_CPU0_SA_DQ<15>")
	)
	(segment
		(start 285.834582 -302.530256)
		(end 285.834582 -303.083468)
		(width 0.18288)
		(layer "In11.Cu")
		(net "M_D_CPU0_SA_DQ<15>")
	)
	(segment
		(start 333.44485 -276.244558)
		(end 332.98765 -276.701758)
		(width 0.088646)
		(layer "In11.Cu")
		(net "M_D_CPU0_SA_DQ<15>")
	)
	(segment
		(start 347.942662 -275.8948)
		(end 347.629988 -275.8948)
		(width 0.088646)
		(layer "In11.Cu")
		(net "M_D_CPU0_SA_DQ<15>")
	)
	(segment
		(start 331.612494 -278.611838)
		(end 330.976986 -278.611838)
		(width 0.088646)
		(layer "In11.Cu")
		(net "M_D_CPU0_SA_DQ<15>")
	)
	(segment
		(start 280.456894 -303.788826)
		(end 280.253694 -303.992026)
		(width 0.18288)
		(layer "In11.Cu")
		(net "M_D_CPU0_SA_DQ<15>")
	)
	(segment
		(start 297.04665 -303.103026)
		(end 296.026586 -303.103026)
		(width 0.18288)
		(layer "In11.Cu")
		(net "M_D_CPU0_SA_DQ<15>")
	)
	(segment
		(start 283.36621 -303.142142)
		(end 283.174694 -302.950626)
		(width 0.18288)
		(layer "In11.Cu")
		(net "M_D_CPU0_SA_DQ<15>")
	)
	(segment
		(start 287.744662 -302.710342)
		(end 287.429702 -302.710342)
		(width 0.18288)
		(layer "In11.Cu")
		(net "M_D_CPU0_SA_DQ<15>")
	)
	(segment
		(start 346.730574 -275.398992)
		(end 346.72016 -275.405088)
		(width 0.088646)
		(layer "In11.Cu")
		(net "M_D_CPU0_SA_DQ<15>")
	)
	(segment
		(start 334.041496 -276.214078)
		(end 334.032606 -276.219158)
		(width 0.088646)
		(layer "In11.Cu")
		(net "M_D_CPU0_SA_DQ<15>")
	)
	(segment
		(start 278.376888 -303.060862)
		(end 277.403814 -303.060862)
		(width 0.18288)
		(layer "In11.Cu")
		(net "M_D_CPU0_SA_DQ<15>")
	)
	(segment
		(start 293.110158 -302.903382)
		(end 293.110158 -303.239678)
		(width 0.18288)
		(layer "In11.Cu")
		(net "M_D_CPU0_SA_DQ<15>")
	)
	(segment
		(start 332.98765 -276.701758)
		(end 332.98765 -277.236682)
		(width 0.088646)
		(layer "In11.Cu")
		(net "M_D_CPU0_SA_DQ<15>")
	)
	(segment
		(start 307.096414 -297.136566)
		(end 306.384706 -297.136566)
		(width 0.18288)
		(layer "In11.Cu")
		(net "M_D_CPU0_SA_DQ<15>")
	)
	(segment
		(start 284.202886 -303.142142)
		(end 283.36621 -303.142142)
		(width 0.18288)
		(layer "In11.Cu")
		(net "M_D_CPU0_SA_DQ<15>")
	)
	(segment
		(start 345.791028 -275.398992)
		(end 345.780614 -275.405088)
		(width 0.088646)
		(layer "In11.Cu")
		(net "M_D_CPU0_SA_DQ<15>")
	)
	(segment
		(start 307.337714 -297.377866)
		(end 307.096414 -297.136566)
		(width 0.18288)
		(layer "In11.Cu")
		(net "M_D_CPU0_SA_DQ<15>")
	)
	(segment
		(start 284.634686 -302.710342)
		(end 284.202886 -303.142142)
		(width 0.18288)
		(layer "In11.Cu")
		(net "M_D_CPU0_SA_DQ<15>")
	)
	(segment
		(start 287.937702 -303.083468)
		(end 287.937702 -302.903382)
		(width 0.18288)
		(layer "In11.Cu")
		(net "M_D_CPU0_SA_DQ<15>")
	)
	(segment
		(start 297.248326 -303.912524)
		(end 297.248326 -303.304702)
		(width 0.18288)
		(layer "In11.Cu")
		(net "M_D_CPU0_SA_DQ<15>")
	)
	(segment
		(start 273.535394 -300.461426)
		(end 272.158968 -299.085)
		(width 0.18288)
		(layer "In11.Cu")
		(net "M_D_CPU0_SA_DQ<15>")
	)
	(segment
		(start 288.831782 -302.710342)
		(end 288.638742 -302.903382)
		(width 0.18288)
		(layer "In11.Cu")
		(net "M_D_CPU0_SA_DQ<15>")
	)
	(segment
		(start 285.133542 -303.083468)
		(end 285.133542 -302.903382)
		(width 0.18288)
		(layer "In11.Cu")
		(net "M_D_CPU0_SA_DQ<15>")
	)
	(segment
		(start 307.873654 -297.377866)
		(end 307.337714 -297.377866)
		(width 0.18288)
		(layer "In11.Cu")
		(net "M_D_CPU0_SA_DQ<15>")
	)
	(segment
		(start 283.174694 -302.950626)
		(end 280.787094 -302.950626)
		(width 0.18288)
		(layer "In11.Cu")
		(net "M_D_CPU0_SA_DQ<15>")
	)
	(segment
		(start 335.45272 -275.398992)
		(end 335.442306 -275.405088)
		(width 0.088646)
		(layer "In11.Cu")
		(net "M_D_CPU0_SA_DQ<15>")
	)
	(segment
		(start 297.949366 -303.912524)
		(end 297.756326 -304.105564)
		(width 0.18288)
		(layer "In11.Cu")
		(net "M_D_CPU0_SA_DQ<15>")
	)
	(segment
		(start 294.381174 -303.862486)
		(end 294.381174 -303.014126)
		(width 0.18288)
		(layer "In11.Cu")
		(net "M_D_CPU0_SA_DQ<15>")
	)
	(segment
		(start 288.638742 -303.083468)
		(end 288.445702 -303.276508)
		(width 0.18288)
		(layer "In11.Cu")
		(net "M_D_CPU0_SA_DQ<15>")
	)
	(segment
		(start 300.910244 -301.039276)
		(end 300.151292 -301.039276)
		(width 0.18288)
		(layer "In11.Cu")
		(net "M_D_CPU0_SA_DQ<15>")
	)
	(segment
		(start 317.799466 -290.92271)
		(end 317.799466 -291.49929)
		(width 0.18288)
		(layer "In11.Cu")
		(net "M_D_CPU0_SA_DQ<15>")
	)
	(segment
		(start 297.441366 -304.105564)
		(end 297.248326 -303.912524)
		(width 0.18288)
		(layer "In11.Cu")
		(net "M_D_CPU0_SA_DQ<15>")
	)
	(segment
		(start 279.308052 -303.992026)
		(end 278.376888 -303.060862)
		(width 0.18288)
		(layer "In11.Cu")
		(net "M_D_CPU0_SA_DQ<15>")
	)
	(segment
		(start 286.036258 -302.32858)
		(end 285.834582 -302.530256)
		(width 0.18288)
		(layer "In11.Cu")
		(net "M_D_CPU0_SA_DQ<15>")
	)
	(segment
		(start 285.326582 -303.276508)
		(end 285.133542 -303.083468)
		(width 0.18288)
		(layer "In11.Cu")
		(net "M_D_CPU0_SA_DQ<15>")
	)
	(segment
		(start 296.026586 -303.103026)
		(end 295.137586 -303.992026)
		(width 0.18288)
		(layer "In11.Cu")
		(net "M_D_CPU0_SA_DQ<15>")
	)
	(segment
		(start 288.638742 -302.903382)
		(end 288.638742 -303.083468)
		(width 0.18288)
		(layer "In11.Cu")
		(net "M_D_CPU0_SA_DQ<15>")
	)
	(segment
		(start 299.606716 -302.94072)
		(end 299.405294 -303.142142)
		(width 0.18288)
		(layer "In11.Cu")
		(net "M_D_CPU0_SA_DQ<15>")
	)
	(segment
		(start 290.093654 -303.56302)
		(end 289.900614 -303.36998)
		(width 0.18288)
		(layer "In11.Cu")
		(net "M_D_CPU0_SA_DQ<15>")
	)
	(segment
		(start 289.707574 -302.710342)
		(end 288.831782 -302.710342)
		(width 0.18288)
		(layer "In11.Cu")
		(net "M_D_CPU0_SA_DQ<15>")
	)
	(segment
		(start 330.976986 -278.611838)
		(end 330.921868 -278.666956)
		(width 0.088646)
		(layer "In11.Cu")
		(net "M_D_CPU0_SA_DQ<15>")
	)
	(segment
		(start 286.342582 -302.32858)
		(end 286.036258 -302.32858)
		(width 0.18288)
		(layer "In11.Cu")
		(net "M_D_CPU0_SA_DQ<15>")
	)
	(segment
		(start 310.687974 -296.130726)
		(end 309.120794 -296.130726)
		(width 0.18288)
		(layer "In11.Cu")
		(net "M_D_CPU0_SA_DQ<15>")
	)
	(segment
		(start 293.303198 -302.710342)
		(end 293.110158 -302.903382)
		(width 0.18288)
		(layer "In11.Cu")
		(net "M_D_CPU0_SA_DQ<15>")
	)
	(segment
		(start 300.151292 -301.039276)
		(end 299.606716 -301.583852)
		(width 0.18288)
		(layer "In11.Cu")
		(net "M_D_CPU0_SA_DQ<15>")
	)
	(segment
		(start 292.602158 -303.432718)
		(end 292.409118 -303.239678)
		(width 0.18288)
		(layer "In11.Cu")
		(net "M_D_CPU0_SA_DQ<15>")
	)
	(segment
		(start 277.403814 -303.060862)
		(end 274.804378 -300.461426)
		(width 0.18288)
		(layer "In11.Cu")
		(net "M_D_CPU0_SA_DQ<15>")
	)
	(segment
		(start 317.799466 -291.49929)
		(end 313.879484 -295.419272)
		(width 0.18288)
		(layer "In11.Cu")
		(net "M_D_CPU0_SA_DQ<15>")
	)
	(segment
		(start 286.535622 -302.52162)
		(end 286.342582 -302.32858)
		(width 0.18288)
		(layer "In11.Cu")
		(net "M_D_CPU0_SA_DQ<15>")
	)
	(segment
		(start 280.787094 -302.950626)
		(end 280.456894 -303.280826)
		(width 0.18288)
		(layer "In11.Cu")
		(net "M_D_CPU0_SA_DQ<15>")
	)
	(segment
		(start 298.151042 -303.142142)
		(end 297.949366 -303.343818)
		(width 0.18288)
		(layer "In11.Cu")
		(net "M_D_CPU0_SA_DQ<15>")
	)
	(segment
		(start 313.879484 -295.419272)
		(end 313.482228 -295.419272)
		(width 0.18288)
		(layer "In11.Cu")
		(net "M_D_CPU0_SA_DQ<15>")
	)
	(segment
		(start 334.220058 -275.876258)
		(end 334.220058 -275.8948)
		(width 0.088646)
		(layer "In11.Cu")
		(net "M_D_CPU0_SA_DQ<15>")
	)
	(segment
		(start 338.272374 -275.398992)
		(end 338.26196 -275.405088)
		(width 0.088646)
		(layer "In11.Cu")
		(net "M_D_CPU0_SA_DQ<15>")
	)
	(segment
		(start 299.606716 -301.583852)
		(end 299.606716 -302.94072)
		(width 0.18288)
		(layer "In11.Cu")
		(net "M_D_CPU0_SA_DQ<15>")
	)
	(segment
		(start 339.212428 -275.398992)
		(end 339.202014 -275.405088)
		(width 0.088646)
		(layer "In11.Cu")
		(net "M_D_CPU0_SA_DQ<15>")
	)
	(segment
		(start 289.900614 -303.36998)
		(end 289.900614 -302.903382)
		(width 0.18288)
		(layer "In11.Cu")
		(net "M_D_CPU0_SA_DQ<15>")
	)
	(segment
		(start 330.921868 -278.666956)
		(end 330.817474 -278.77135)
		(width 0.18288)
		(layer "In11.Cu")
		(net "M_D_CPU0_SA_DQ<15>")
	)
	(segment
		(start 297.756326 -304.105564)
		(end 297.441366 -304.105564)
		(width 0.18288)
		(layer "In11.Cu")
		(net "M_D_CPU0_SA_DQ<15>")
	)
	(segment
		(start 292.409118 -303.239678)
		(end 292.409118 -302.903382)
		(width 0.18288)
		(layer "In11.Cu")
		(net "M_D_CPU0_SA_DQ<15>")
	)
	(segment
		(start 297.949366 -303.343818)
		(end 297.949366 -303.912524)
		(width 0.18288)
		(layer "In11.Cu")
		(net "M_D_CPU0_SA_DQ<15>")
	)
	(segment
		(start 312.417714 -296.483786)
		(end 311.041034 -296.483786)
		(width 0.18288)
		(layer "In11.Cu")
		(net "M_D_CPU0_SA_DQ<15>")
	)
	(segment
		(start 341.096346 -275.396452)
		(end 341.081614 -275.405088)
		(width 0.088646)
		(layer "In11.Cu")
		(net "M_D_CPU0_SA_DQ<15>")
	)
	(segment
		(start 287.937702 -302.903382)
		(end 287.744662 -302.710342)
		(width 0.18288)
		(layer "In11.Cu")
		(net "M_D_CPU0_SA_DQ<15>")
	)
	(arc
		(start 342.961214 -275.405088)
		(mid 342.774016 -275.455231)
		(end 342.586818 -275.405088)
		(width 0.088646)
		(layer "In11.Cu")
		(net "M_D_CPU0_SA_DQ<15>")
	)
	(arc
		(start 343.526618 -275.405088)
		(mid 343.252389 -275.329163)
		(end 342.975946 -275.396452)
		(width 0.088646)
		(layer "In11.Cu")
		(net "M_D_CPU0_SA_DQ<15>")
	)
	(arc
		(start 345.780614 -275.405088)
		(mid 345.593416 -275.455231)
		(end 345.406218 -275.405088)
		(width 0.088646)
		(layer "In11.Cu")
		(net "M_D_CPU0_SA_DQ<15>")
	)
	(arc
		(start 339.202014 -275.405088)
		(mid 339.014816 -275.455231)
		(end 338.827618 -275.405088)
		(width 0.088646)
		(layer "In11.Cu")
		(net "M_D_CPU0_SA_DQ<15>")
	)
	(arc
		(start 347.285818 -275.405088)
		(mid 347.009005 -275.329252)
		(end 346.730574 -275.398992)
		(width 0.088646)
		(layer "In11.Cu")
		(net "M_D_CPU0_SA_DQ<15>")
	)
	(arc
		(start 346.345764 -275.405088)
		(mid 346.069205 -275.329379)
		(end 345.791028 -275.398992)
		(width 0.088646)
		(layer "In11.Cu")
		(net "M_D_CPU0_SA_DQ<15>")
	)
	(arc
		(start 344.840814 -275.405088)
		(mid 344.653616 -275.455231)
		(end 344.466418 -275.405088)
		(width 0.088646)
		(layer "In11.Cu")
		(net "M_D_CPU0_SA_DQ<15>")
	)
	(arc
		(start 337.887564 -275.405088)
		(mid 337.604862 -275.329346)
		(end 337.32216 -275.405088)
		(width 0.088646)
		(layer "In11.Cu")
		(net "M_D_CPU0_SA_DQ<15>")
	)
	(arc
		(start 343.901014 -275.405088)
		(mid 343.713816 -275.455231)
		(end 343.526618 -275.405088)
		(width 0.088646)
		(layer "In11.Cu")
		(net "M_D_CPU0_SA_DQ<15>")
	)
	(arc
		(start 334.502506 -275.405088)
		(mid 334.30022 -275.604069)
		(end 334.220058 -275.876258)
		(width 0.088646)
		(layer "In11.Cu")
		(net "M_D_CPU0_SA_DQ<15>")
	)
	(arc
		(start 341.647018 -275.405088)
		(mid 341.372789 -275.329163)
		(end 341.096346 -275.396452)
		(width 0.088646)
		(layer "In11.Cu")
		(net "M_D_CPU0_SA_DQ<15>")
	)
	(arc
		(start 341.081614 -275.405088)
		(mid 340.894416 -275.455231)
		(end 340.707218 -275.405088)
		(width 0.088646)
		(layer "In11.Cu")
		(net "M_D_CPU0_SA_DQ<15>")
	)
	(arc
		(start 333.749904 -276.257004)
		(mid 333.702554 -276.247694)
		(end 333.6544 -276.244558)
		(width 0.088646)
		(layer "In11.Cu")
		(net "M_D_CPU0_SA_DQ<15>")
	)
	(arc
		(start 342.021414 -275.405088)
		(mid 341.834216 -275.455231)
		(end 341.647018 -275.405088)
		(width 0.088646)
		(layer "In11.Cu")
		(net "M_D_CPU0_SA_DQ<15>")
	)
	(arc
		(start 335.06791 -275.405088)
		(mid 334.785208 -275.329346)
		(end 334.502506 -275.405088)
		(width 0.088646)
		(layer "In11.Cu")
		(net "M_D_CPU0_SA_DQ<15>")
	)
	(arc
		(start 340.14156 -275.405088)
		(mid 339.954362 -275.455231)
		(end 339.767164 -275.405088)
		(width 0.088646)
		(layer "In11.Cu")
		(net "M_D_CPU0_SA_DQ<15>")
	)
	(arc
		(start 345.406218 -275.405088)
		(mid 345.131989 -275.329163)
		(end 344.855546 -275.396452)
		(width 0.088646)
		(layer "In11.Cu")
		(net "M_D_CPU0_SA_DQ<15>")
	)
	(arc
		(start 336.38236 -275.405088)
		(mid 336.195162 -275.455231)
		(end 336.007964 -275.405088)
		(width 0.088646)
		(layer "In11.Cu")
		(net "M_D_CPU0_SA_DQ<15>")
	)
	(arc
		(start 346.72016 -275.405088)
		(mid 346.532962 -275.455231)
		(end 346.345764 -275.405088)
		(width 0.088646)
		(layer "In11.Cu")
		(net "M_D_CPU0_SA_DQ<15>")
	)
	(arc
		(start 337.32216 -275.405088)
		(mid 337.134962 -275.455231)
		(end 336.947764 -275.405088)
		(width 0.088646)
		(layer "In11.Cu")
		(net "M_D_CPU0_SA_DQ<15>")
	)
	(arc
		(start 338.26196 -275.405088)
		(mid 338.074762 -275.455231)
		(end 337.887564 -275.405088)
		(width 0.088646)
		(layer "In11.Cu")
		(net "M_D_CPU0_SA_DQ<15>")
	)
	(arc
		(start 334.220058 -275.8948)
		(mid 334.172379 -276.0777)
		(end 334.041496 -276.214078)
		(width 0.088646)
		(layer "In11.Cu")
		(net "M_D_CPU0_SA_DQ<15>")
	)
	(arc
		(start 339.767164 -275.405088)
		(mid 339.490605 -275.329379)
		(end 339.212428 -275.398992)
		(width 0.088646)
		(layer "In11.Cu")
		(net "M_D_CPU0_SA_DQ<15>")
	)
	(arc
		(start 344.466418 -275.405088)
		(mid 344.192189 -275.329163)
		(end 343.915746 -275.396452)
		(width 0.088646)
		(layer "In11.Cu")
		(net "M_D_CPU0_SA_DQ<15>")
	)
	(arc
		(start 336.007964 -275.405088)
		(mid 335.731151 -275.329252)
		(end 335.45272 -275.398992)
		(width 0.088646)
		(layer "In11.Cu")
		(net "M_D_CPU0_SA_DQ<15>")
	)
	(arc
		(start 340.707218 -275.405088)
		(mid 340.430405 -275.329252)
		(end 340.151974 -275.398992)
		(width 0.088646)
		(layer "In11.Cu")
		(net "M_D_CPU0_SA_DQ<15>")
	)
	(arc
		(start 335.442306 -275.405088)
		(mid 335.255108 -275.455231)
		(end 335.06791 -275.405088)
		(width 0.088646)
		(layer "In11.Cu")
		(net "M_D_CPU0_SA_DQ<15>")
	)
	(arc
		(start 334.032606 -276.219158)
		(mid 333.895001 -276.266003)
		(end 333.749904 -276.257004)
		(width 0.088646)
		(layer "In11.Cu")
		(net "M_D_CPU0_SA_DQ<15>")
	)
	(arc
		(start 336.947764 -275.405088)
		(mid 336.665062 -275.329346)
		(end 336.38236 -275.405088)
		(width 0.088646)
		(layer "In11.Cu")
		(net "M_D_CPU0_SA_DQ<15>")
	)
	(arc
		(start 342.586818 -275.405088)
		(mid 342.304116 -275.329346)
		(end 342.021414 -275.405088)
		(width 0.088646)
		(layer "In11.Cu")
		(net "M_D_CPU0_SA_DQ<15>")
	)
	(arc
		(start 338.827618 -275.405088)
		(mid 338.550805 -275.329252)
		(end 338.272374 -275.398992)
		(width 0.088646)
		(layer "In11.Cu")
		(net "M_D_CPU0_SA_DQ<15>")
	)
	(arc
		(start 347.56471 -275.829522)
		(mid 347.475596 -275.584225)
		(end 347.285818 -275.405088)
		(width 0.088646)
		(layer "In11.Cu")
		(net "M_D_CPU0_SA_DQ<15>")
	)
	(segment
		(start 262.51027 -299.741844)
		(end 262.50011 -299.731684)
		(width 0.101854)
		(layer "F.Cu")
		(net "M_D_CPU0_SA_DQ<14>")
	)
	(segment
		(start 265.769344 -300.378622)
		(end 265.601958 -300.211236)
		(width 0.20066)
		(layer "F.Cu")
		(net "M_D_CPU0_SA_DQ<14>")
	)
	(segment
		(start 265.458194 -299.741844)
		(end 264.825226 -299.741844)
		(width 0.20066)
		(layer "F.Cu")
		(net "M_D_CPU0_SA_DQ<14>")
	)
	(segment
		(start 264.825226 -299.741844)
		(end 262.765286 -299.741844)
		(width 0.1016)
		(layer "F.Cu")
		(net "M_D_CPU0_SA_DQ<14>")
	)
	(segment
		(start 348.412562 -276.708362)
		(end 348.412816 -276.708616)
		(width 0.20066)
		(layer "F.Cu")
		(net "M_D_CPU0_SA_DQ<14>")
	)
	(segment
		(start 266.409678 -300.166786)
		(end 266.197842 -300.378622)
		(width 0.20066)
		(layer "F.Cu")
		(net "M_D_CPU0_SA_DQ<14>")
	)
	(segment
		(start 267.724382 -300.166786)
		(end 266.409678 -300.166786)
		(width 0.20066)
		(layer "F.Cu")
		(net "M_D_CPU0_SA_DQ<14>")
	)
	(segment
		(start 262.765286 -299.741844)
		(end 262.51027 -299.741844)
		(width 0.101854)
		(layer "F.Cu")
		(net "M_D_CPU0_SA_DQ<14>")
	)
	(segment
		(start 265.601958 -299.885608)
		(end 265.458194 -299.741844)
		(width 0.20066)
		(layer "F.Cu")
		(net "M_D_CPU0_SA_DQ<14>")
	)
	(segment
		(start 266.197842 -300.378622)
		(end 265.769344 -300.378622)
		(width 0.20066)
		(layer "F.Cu")
		(net "M_D_CPU0_SA_DQ<14>")
	)
	(segment
		(start 268.829282 -300.166786)
		(end 267.724382 -300.166786)
		(width 0.20066)
		(layer "F.Cu")
		(net "M_D_CPU0_SA_DQ<14>")
	)
	(segment
		(start 265.601958 -300.211236)
		(end 265.601958 -299.885608)
		(width 0.20066)
		(layer "F.Cu")
		(net "M_D_CPU0_SA_DQ<14>")
	)
	(segment
		(start 348.412562 -276.172676)
		(end 348.412562 -276.708362)
		(width 0.20066)
		(layer "F.Cu")
		(net "M_D_CPU0_SA_DQ<14>")
	)
	(segment
		(start 261.327646 -300.166786)
		(end 260.180582 -300.166786)
		(width 0.20066)
		(layer "F.Cu")
		(net "M_D_CPU0_SA_DQ<14>")
	)
	(segment
		(start 262.50011 -299.731684)
		(end 261.762748 -299.731684)
		(width 0.20066)
		(layer "F.Cu")
		(net "M_D_CPU0_SA_DQ<14>")
	)
	(segment
		(start 261.762748 -299.731684)
		(end 261.327646 -300.166786)
		(width 0.20066)
		(layer "F.Cu")
		(net "M_D_CPU0_SA_DQ<14>")
	)
	(segment
		(start 334.690212 -276.693122)
		(end 334.690212 -276.708616)
		(width 0.088646)
		(layer "In11.Cu")
		(net "M_D_CPU0_SA_DQ<14>")
	)
	(segment
		(start 279.126442 -306.078636)
		(end 278.933402 -306.271676)
		(width 0.18288)
		(layer "In11.Cu")
		(net "M_D_CPU0_SA_DQ<14>")
	)
	(segment
		(start 314.679584 -297.073066)
		(end 313.33313 -297.073066)
		(width 0.18288)
		(layer "In11.Cu")
		(net "M_D_CPU0_SA_DQ<14>")
	)
	(segment
		(start 276.264116 -304.122328)
		(end 275.905214 -303.763426)
		(width 0.18288)
		(layer "In11.Cu")
		(net "M_D_CPU0_SA_DQ<14>")
	)
	(segment
		(start 276.657054 -304.122328)
		(end 276.264116 -304.122328)
		(width 0.18288)
		(layer "In11.Cu")
		(net "M_D_CPU0_SA_DQ<14>")
	)
	(segment
		(start 290.747196 -304.897536)
		(end 290.554156 -304.704496)
		(width 0.18288)
		(layer "In11.Cu")
		(net "M_D_CPU0_SA_DQ<14>")
	)
	(segment
		(start 331.190854 -279.837896)
		(end 330.32192 -279.837896)
		(width 0.18288)
		(layer "In11.Cu")
		(net "M_D_CPU0_SA_DQ<14>")
	)
	(segment
		(start 312.23077 -298.175426)
		(end 311.104534 -298.175426)
		(width 0.18288)
		(layer "In11.Cu")
		(net "M_D_CPU0_SA_DQ<14>")
	)
	(segment
		(start 272.415254 -301.220886)
		(end 271.577054 -301.220886)
		(width 0.18288)
		(layer "In11.Cu")
		(net "M_D_CPU0_SA_DQ<14>")
	)
	(segment
		(start 287.876488 -305.034696)
		(end 284.598364 -305.034696)
		(width 0.18288)
		(layer "In11.Cu")
		(net "M_D_CPU0_SA_DQ<14>")
	)
	(segment
		(start 275.905214 -303.763426)
		(end 275.905214 -303.306226)
		(width 0.18288)
		(layer "In11.Cu")
		(net "M_D_CPU0_SA_DQ<14>")
	)
	(segment
		(start 284.405324 -304.841656)
		(end 283.52242 -304.841656)
		(width 0.18288)
		(layer "In11.Cu")
		(net "M_D_CPU0_SA_DQ<14>")
	)
	(segment
		(start 301.83836 -303.042828)
		(end 301.356014 -302.560482)
		(width 0.18288)
		(layer "In11.Cu")
		(net "M_D_CPU0_SA_DQ<14>")
	)
	(segment
		(start 278.232362 -305.69154)
		(end 277.912576 -305.69154)
		(width 0.18288)
		(layer "In11.Cu")
		(net "M_D_CPU0_SA_DQ<14>")
	)
	(segment
		(start 281.089354 -305.010566)
		(end 281.089354 -305.424586)
		(width 0.18288)
		(layer "In11.Cu")
		(net "M_D_CPU0_SA_DQ<14>")
	)
	(segment
		(start 334.51165 -277.027894)
		(end 334.50276 -277.032974)
		(width 0.088646)
		(layer "In11.Cu")
		(net "M_D_CPU0_SA_DQ<14>")
	)
	(segment
		(start 301.851822 -301.791878)
		(end 301.851822 -302.064674)
		(width 0.18288)
		(layer "In11.Cu")
		(net "M_D_CPU0_SA_DQ<14>")
	)
	(segment
		(start 277.912576 -305.69154)
		(end 277.462742 -305.241706)
		(width 0.18288)
		(layer "In11.Cu")
		(net "M_D_CPU0_SA_DQ<14>")
	)
	(segment
		(start 309.156354 -297.888406)
		(end 308.059074 -298.985686)
		(width 0.18288)
		(layer "In11.Cu")
		(net "M_D_CPU0_SA_DQ<14>")
	)
	(segment
		(start 275.905214 -303.306226)
		(end 274.609814 -302.010826)
		(width 0.18288)
		(layer "In11.Cu")
		(net "M_D_CPU0_SA_DQ<14>")
	)
	(segment
		(start 346.815664 -276.219158)
		(end 346.800932 -276.210522)
		(width 0.088646)
		(layer "In11.Cu")
		(net "M_D_CPU0_SA_DQ<14>")
	)
	(segment
		(start 331.576934 -279.451816)
		(end 331.190854 -279.837896)
		(width 0.18288)
		(layer "In11.Cu")
		(net "M_D_CPU0_SA_DQ<14>")
	)
	(segment
		(start 290.239196 -304.704496)
		(end 290.046156 -304.897536)
		(width 0.18288)
		(layer "In11.Cu")
		(net "M_D_CPU0_SA_DQ<14>")
	)
	(segment
		(start 277.462742 -305.241706)
		(end 277.462742 -304.928016)
		(width 0.18288)
		(layer "In11.Cu")
		(net "M_D_CPU0_SA_DQ<14>")
	)
	(segment
		(start 297.992292 -305.412648)
		(end 296.988992 -305.828192)
		(width 0.18288)
		(layer "In11.Cu")
		(net "M_D_CPU0_SA_DQ<14>")
	)
	(segment
		(start 290.046156 -305.579018)
		(end 289.853116 -305.772058)
		(width 0.18288)
		(layer "In11.Cu")
		(net "M_D_CPU0_SA_DQ<14>")
	)
	(segment
		(start 280.505154 -306.018946)
		(end 280.177748 -305.69154)
		(width 0.18288)
		(layer "In11.Cu")
		(net "M_D_CPU0_SA_DQ<14>")
	)
	(segment
		(start 333.386176 -277.10638)
		(end 333.386176 -277.427436)
		(width 0.088646)
		(layer "In11.Cu")
		(net "M_D_CPU0_SA_DQ<14>")
	)
	(segment
		(start 278.618442 -306.271676)
		(end 278.425402 -306.078636)
		(width 0.18288)
		(layer "In11.Cu")
		(net "M_D_CPU0_SA_DQ<14>")
	)
	(segment
		(start 280.177748 -305.69154)
		(end 279.319482 -305.69154)
		(width 0.18288)
		(layer "In11.Cu")
		(net "M_D_CPU0_SA_DQ<14>")
	)
	(segment
		(start 292.432994 -304.995326)
		(end 291.656262 -305.772058)
		(width 0.18288)
		(layer "In11.Cu")
		(net "M_D_CPU0_SA_DQ<14>")
	)
	(segment
		(start 336.477864 -276.219158)
		(end 336.46745 -276.213062)
		(width 0.088646)
		(layer "In11.Cu")
		(net "M_D_CPU0_SA_DQ<14>")
	)
	(segment
		(start 313.33313 -297.073066)
		(end 312.23077 -298.175426)
		(width 0.18288)
		(layer "In11.Cu")
		(net "M_D_CPU0_SA_DQ<14>")
	)
	(segment
		(start 281.234134 -305.861466)
		(end 281.076654 -306.018946)
		(width 0.18288)
		(layer "In11.Cu")
		(net "M_D_CPU0_SA_DQ<14>")
	)
	(segment
		(start 310.817514 -297.888406)
		(end 309.156354 -297.888406)
		(width 0.18288)
		(layer "In11.Cu")
		(net "M_D_CPU0_SA_DQ<14>")
	)
	(segment
		(start 293.47668 -304.995326)
		(end 292.432994 -304.995326)
		(width 0.18288)
		(layer "In11.Cu")
		(net "M_D_CPU0_SA_DQ<14>")
	)
	(segment
		(start 302.420274 -301.223426)
		(end 301.851822 -301.791878)
		(width 0.18288)
		(layer "In11.Cu")
		(net "M_D_CPU0_SA_DQ<14>")
	)
	(segment
		(start 302.111156 -303.042828)
		(end 301.83836 -303.042828)
		(width 0.18288)
		(layer "In11.Cu")
		(net "M_D_CPU0_SA_DQ<14>")
	)
	(segment
		(start 301.356014 -302.560482)
		(end 301.083218 -302.560482)
		(width 0.18288)
		(layer "In11.Cu")
		(net "M_D_CPU0_SA_DQ<14>")
	)
	(segment
		(start 281.089354 -305.424586)
		(end 281.234134 -305.569366)
		(width 0.18288)
		(layer "In11.Cu")
		(net "M_D_CPU0_SA_DQ<14>")
	)
	(segment
		(start 331.808836 -279.004776)
		(end 331.808836 -279.219914)
		(width 0.088646)
		(layer "In11.Cu")
		(net "M_D_CPU0_SA_DQ<14>")
	)
	(segment
		(start 302.334168 -302.54702)
		(end 302.334168 -302.819816)
		(width 0.18288)
		(layer "In11.Cu")
		(net "M_D_CPU0_SA_DQ<14>")
	)
	(segment
		(start 289.853116 -305.772058)
		(end 288.61385 -305.772058)
		(width 0.18288)
		(layer "In11.Cu")
		(net "M_D_CPU0_SA_DQ<14>")
	)
	(segment
		(start 281.234134 -305.569366)
		(end 281.234134 -305.861466)
		(width 0.18288)
		(layer "In11.Cu")
		(net "M_D_CPU0_SA_DQ<14>")
	)
	(segment
		(start 318.873124 -291.286692)
		(end 318.873124 -291.990272)
		(width 0.18288)
		(layer "In11.Cu")
		(net "M_D_CPU0_SA_DQ<14>")
	)
	(segment
		(start 306.275994 -298.835826)
		(end 304.624994 -300.486826)
		(width 0.18288)
		(layer "In11.Cu")
		(net "M_D_CPU0_SA_DQ<14>")
	)
	(segment
		(start 344.936064 -276.219158)
		(end 344.921332 -276.210522)
		(width 0.088646)
		(layer "In11.Cu")
		(net "M_D_CPU0_SA_DQ<14>")
	)
	(segment
		(start 308.059074 -298.985686)
		(end 307.439314 -298.985686)
		(width 0.18288)
		(layer "In11.Cu")
		(net "M_D_CPU0_SA_DQ<14>")
	)
	(segment
		(start 333.845408 -276.957028)
		(end 333.535528 -276.957028)
		(width 0.088646)
		(layer "In11.Cu")
		(net "M_D_CPU0_SA_DQ<14>")
	)
	(segment
		(start 281.422094 -304.677826)
		(end 281.089354 -305.010566)
		(width 0.18288)
		(layer "In11.Cu")
		(net "M_D_CPU0_SA_DQ<14>")
	)
	(segment
		(start 311.104534 -298.175426)
		(end 310.817514 -297.888406)
		(width 0.18288)
		(layer "In11.Cu")
		(net "M_D_CPU0_SA_DQ<14>")
	)
	(segment
		(start 342.116918 -276.219158)
		(end 342.106504 -276.213062)
		(width 0.088646)
		(layer "In11.Cu")
		(net "M_D_CPU0_SA_DQ<14>")
	)
	(segment
		(start 288.61385 -305.772058)
		(end 287.876488 -305.034696)
		(width 0.18288)
		(layer "In11.Cu")
		(net "M_D_CPU0_SA_DQ<14>")
	)
	(segment
		(start 269.42669 -300.764194)
		(end 268.829282 -300.166786)
		(width 0.18288)
		(layer "In11.Cu")
		(net "M_D_CPU0_SA_DQ<14>")
	)
	(segment
		(start 279.319482 -305.69154)
		(end 279.126442 -305.88458)
		(width 0.18288)
		(layer "In11.Cu")
		(net "M_D_CPU0_SA_DQ<14>")
	)
	(segment
		(start 330.32192 -279.837896)
		(end 318.873124 -291.286692)
		(width 0.18288)
		(layer "In11.Cu")
		(net "M_D_CPU0_SA_DQ<14>")
	)
	(segment
		(start 290.554156 -304.704496)
		(end 290.239196 -304.704496)
		(width 0.18288)
		(layer "In11.Cu")
		(net "M_D_CPU0_SA_DQ<14>")
	)
	(segment
		(start 341.176864 -276.219158)
		(end 341.162132 -276.210522)
		(width 0.088646)
		(layer "In11.Cu")
		(net "M_D_CPU0_SA_DQ<14>")
	)
	(segment
		(start 301.083218 -302.560482)
		(end 300.853094 -302.790606)
		(width 0.18288)
		(layer "In11.Cu")
		(net "M_D_CPU0_SA_DQ<14>")
	)
	(segment
		(start 296.988992 -305.828192)
		(end 295.86174 -305.828192)
		(width 0.18288)
		(layer "In11.Cu")
		(net "M_D_CPU0_SA_DQ<14>")
	)
	(segment
		(start 273.205194 -302.010826)
		(end 272.415254 -301.220886)
		(width 0.18288)
		(layer "In11.Cu")
		(net "M_D_CPU0_SA_DQ<14>")
	)
	(segment
		(start 295.725088 -305.69154)
		(end 294.172894 -305.69154)
		(width 0.18288)
		(layer "In11.Cu")
		(net "M_D_CPU0_SA_DQ<14>")
	)
	(segment
		(start 300.853094 -304.500026)
		(end 300.374812 -304.978308)
		(width 0.18288)
		(layer "In11.Cu")
		(net "M_D_CPU0_SA_DQ<14>")
	)
	(segment
		(start 307.439314 -298.985686)
		(end 307.289454 -298.835826)
		(width 0.18288)
		(layer "In11.Cu")
		(net "M_D_CPU0_SA_DQ<14>")
	)
	(segment
		(start 307.289454 -298.835826)
		(end 306.275994 -298.835826)
		(width 0.18288)
		(layer "In11.Cu")
		(net "M_D_CPU0_SA_DQ<14>")
	)
	(segment
		(start 299.49013 -304.978308)
		(end 299.353478 -304.841656)
		(width 0.18288)
		(layer "In11.Cu")
		(net "M_D_CPU0_SA_DQ<14>")
	)
	(segment
		(start 290.747196 -305.579018)
		(end 290.747196 -304.897536)
		(width 0.18288)
		(layer "In11.Cu")
		(net "M_D_CPU0_SA_DQ<14>")
	)
	(segment
		(start 278.933402 -306.271676)
		(end 278.618442 -306.271676)
		(width 0.18288)
		(layer "In11.Cu")
		(net "M_D_CPU0_SA_DQ<14>")
	)
	(segment
		(start 278.425402 -305.88458)
		(end 278.232362 -305.69154)
		(width 0.18288)
		(layer "In11.Cu")
		(net "M_D_CPU0_SA_DQ<14>")
	)
	(segment
		(start 271.120362 -300.764194)
		(end 269.42669 -300.764194)
		(width 0.18288)
		(layer "In11.Cu")
		(net "M_D_CPU0_SA_DQ<14>")
	)
	(segment
		(start 283.35859 -304.677826)
		(end 281.422094 -304.677826)
		(width 0.18288)
		(layer "In11.Cu")
		(net "M_D_CPU0_SA_DQ<14>")
	)
	(segment
		(start 303.189894 -301.223426)
		(end 302.420274 -301.223426)
		(width 0.18288)
		(layer "In11.Cu")
		(net "M_D_CPU0_SA_DQ<14>")
	)
	(segment
		(start 279.126442 -305.88458)
		(end 279.126442 -306.078636)
		(width 0.18288)
		(layer "In11.Cu")
		(net "M_D_CPU0_SA_DQ<14>")
	)
	(segment
		(start 284.598364 -305.034696)
		(end 284.405324 -304.841656)
		(width 0.18288)
		(layer "In11.Cu")
		(net "M_D_CPU0_SA_DQ<14>")
	)
	(segment
		(start 303.926494 -300.486826)
		(end 303.189894 -301.223426)
		(width 0.18288)
		(layer "In11.Cu")
		(net "M_D_CPU0_SA_DQ<14>")
	)
	(segment
		(start 301.851822 -302.064674)
		(end 302.334168 -302.54702)
		(width 0.18288)
		(layer "In11.Cu")
		(net "M_D_CPU0_SA_DQ<14>")
	)
	(segment
		(start 294.172894 -305.69154)
		(end 293.47668 -304.995326)
		(width 0.18288)
		(layer "In11.Cu")
		(net "M_D_CPU0_SA_DQ<14>")
	)
	(segment
		(start 333.535528 -276.957028)
		(end 333.386176 -277.10638)
		(width 0.088646)
		(layer "In11.Cu")
		(net "M_D_CPU0_SA_DQ<14>")
	)
	(segment
		(start 343.056464 -276.219158)
		(end 343.04605 -276.213062)
		(width 0.088646)
		(layer "In11.Cu")
		(net "M_D_CPU0_SA_DQ<14>")
	)
	(segment
		(start 271.577054 -301.220886)
		(end 271.120362 -300.764194)
		(width 0.18288)
		(layer "In11.Cu")
		(net "M_D_CPU0_SA_DQ<14>")
	)
	(segment
		(start 300.374812 -304.978308)
		(end 299.49013 -304.978308)
		(width 0.18288)
		(layer "In11.Cu")
		(net "M_D_CPU0_SA_DQ<14>")
	)
	(segment
		(start 298.563284 -304.841656)
		(end 297.992292 -305.412648)
		(width 0.18288)
		(layer "In11.Cu")
		(net "M_D_CPU0_SA_DQ<14>")
	)
	(segment
		(start 295.86174 -305.828192)
		(end 295.725088 -305.69154)
		(width 0.18288)
		(layer "In11.Cu")
		(net "M_D_CPU0_SA_DQ<14>")
	)
	(segment
		(start 340.237064 -276.219158)
		(end 340.222332 -276.210522)
		(width 0.088646)
		(layer "In11.Cu")
		(net "M_D_CPU0_SA_DQ<14>")
	)
	(segment
		(start 274.609814 -302.010826)
		(end 273.205194 -302.010826)
		(width 0.18288)
		(layer "In11.Cu")
		(net "M_D_CPU0_SA_DQ<14>")
	)
	(segment
		(start 291.656262 -305.772058)
		(end 290.940236 -305.772058)
		(width 0.18288)
		(layer "In11.Cu")
		(net "M_D_CPU0_SA_DQ<14>")
	)
	(segment
		(start 281.076654 -306.018946)
		(end 280.505154 -306.018946)
		(width 0.18288)
		(layer "In11.Cu")
		(net "M_D_CPU0_SA_DQ<14>")
	)
	(segment
		(start 299.353478 -304.841656)
		(end 298.563284 -304.841656)
		(width 0.18288)
		(layer "In11.Cu")
		(net "M_D_CPU0_SA_DQ<14>")
	)
	(segment
		(start 278.425402 -306.078636)
		(end 278.425402 -305.88458)
		(width 0.18288)
		(layer "In11.Cu")
		(net "M_D_CPU0_SA_DQ<14>")
	)
	(segment
		(start 277.462742 -304.928016)
		(end 276.657054 -304.122328)
		(width 0.18288)
		(layer "In11.Cu")
		(net "M_D_CPU0_SA_DQ<14>")
	)
	(segment
		(start 333.386176 -277.427436)
		(end 331.808836 -279.004776)
		(width 0.088646)
		(layer "In11.Cu")
		(net "M_D_CPU0_SA_DQ<14>")
	)
	(segment
		(start 304.624994 -300.486826)
		(end 303.926494 -300.486826)
		(width 0.18288)
		(layer "In11.Cu")
		(net "M_D_CPU0_SA_DQ<14>")
	)
	(segment
		(start 315.131196 -296.621454)
		(end 314.679584 -297.073066)
		(width 0.18288)
		(layer "In11.Cu")
		(net "M_D_CPU0_SA_DQ<14>")
	)
	(segment
		(start 290.940236 -305.772058)
		(end 290.747196 -305.579018)
		(width 0.18288)
		(layer "In11.Cu")
		(net "M_D_CPU0_SA_DQ<14>")
	)
	(segment
		(start 315.131196 -295.7322)
		(end 315.131196 -296.621454)
		(width 0.18288)
		(layer "In11.Cu")
		(net "M_D_CPU0_SA_DQ<14>")
	)
	(segment
		(start 300.853094 -302.790606)
		(end 300.853094 -304.500026)
		(width 0.18288)
		(layer "In11.Cu")
		(net "M_D_CPU0_SA_DQ<14>")
	)
	(segment
		(start 335.53781 -276.219158)
		(end 335.523078 -276.210522)
		(width 0.088646)
		(layer "In11.Cu")
		(net "M_D_CPU0_SA_DQ<14>")
	)
	(segment
		(start 283.52242 -304.841656)
		(end 283.35859 -304.677826)
		(width 0.18288)
		(layer "In11.Cu")
		(net "M_D_CPU0_SA_DQ<14>")
	)
	(segment
		(start 331.808836 -279.219914)
		(end 331.576934 -279.451816)
		(width 0.088646)
		(layer "In11.Cu")
		(net "M_D_CPU0_SA_DQ<14>")
	)
	(segment
		(start 347.85427 -276.27707)
		(end 347.740732 -276.210522)
		(width 0.088646)
		(layer "In11.Cu")
		(net "M_D_CPU0_SA_DQ<14>")
	)
	(segment
		(start 290.046156 -304.897536)
		(end 290.046156 -305.579018)
		(width 0.18288)
		(layer "In11.Cu")
		(net "M_D_CPU0_SA_DQ<14>")
	)
	(segment
		(start 302.334168 -302.819816)
		(end 302.111156 -303.042828)
		(width 0.18288)
		(layer "In11.Cu")
		(net "M_D_CPU0_SA_DQ<14>")
	)
	(segment
		(start 343.996264 -276.219158)
		(end 343.981532 -276.210522)
		(width 0.088646)
		(layer "In11.Cu")
		(net "M_D_CPU0_SA_DQ<14>")
	)
	(segment
		(start 318.873124 -291.990272)
		(end 315.131196 -295.7322)
		(width 0.18288)
		(layer "In11.Cu")
		(net "M_D_CPU0_SA_DQ<14>")
	)
	(arc
		(start 337.417664 -276.219158)
		(mid 337.134962 -276.143382)
		(end 336.85226 -276.219158)
		(width 0.088646)
		(layer "In11.Cu")
		(net "M_D_CPU0_SA_DQ<14>")
	)
	(arc
		(start 338.357464 -276.219158)
		(mid 338.074762 -276.143382)
		(end 337.79206 -276.219158)
		(width 0.088646)
		(layer "In11.Cu")
		(net "M_D_CPU0_SA_DQ<14>")
	)
	(arc
		(start 345.875864 -276.219158)
		(mid 345.593162 -276.143382)
		(end 345.31046 -276.219158)
		(width 0.088646)
		(layer "In11.Cu")
		(net "M_D_CPU0_SA_DQ<14>")
	)
	(arc
		(start 340.61146 -276.219158)
		(mid 340.424262 -276.269301)
		(end 340.237064 -276.219158)
		(width 0.088646)
		(layer "In11.Cu")
		(net "M_D_CPU0_SA_DQ<14>")
	)
	(arc
		(start 339.297264 -276.219158)
		(mid 339.014562 -276.143382)
		(end 338.73186 -276.219158)
		(width 0.088646)
		(layer "In11.Cu")
		(net "M_D_CPU0_SA_DQ<14>")
	)
	(arc
		(start 339.67166 -276.219158)
		(mid 339.484462 -276.269301)
		(end 339.297264 -276.219158)
		(width 0.088646)
		(layer "In11.Cu")
		(net "M_D_CPU0_SA_DQ<14>")
	)
	(arc
		(start 343.04605 -276.213062)
		(mid 342.767872 -276.143339)
		(end 342.491314 -276.219158)
		(width 0.088646)
		(layer "In11.Cu")
		(net "M_D_CPU0_SA_DQ<14>")
	)
	(arc
		(start 347.740732 -276.210522)
		(mid 347.464257 -276.143202)
		(end 347.19006 -276.219158)
		(width 0.088646)
		(layer "In11.Cu")
		(net "M_D_CPU0_SA_DQ<14>")
	)
	(arc
		(start 336.85226 -276.219158)
		(mid 336.665062 -276.269301)
		(end 336.477864 -276.219158)
		(width 0.088646)
		(layer "In11.Cu")
		(net "M_D_CPU0_SA_DQ<14>")
	)
	(arc
		(start 348.412816 -276.708616)
		(mid 348.147325 -276.475005)
		(end 347.85427 -276.27707)
		(width 0.088646)
		(layer "In11.Cu")
		(net "M_D_CPU0_SA_DQ<14>")
	)
	(arc
		(start 335.912206 -276.219158)
		(mid 335.725008 -276.269301)
		(end 335.53781 -276.219158)
		(width 0.088646)
		(layer "In11.Cu")
		(net "M_D_CPU0_SA_DQ<14>")
	)
	(arc
		(start 335.523078 -276.210522)
		(mid 335.246603 -276.143202)
		(end 334.972406 -276.219158)
		(width 0.088646)
		(layer "In11.Cu")
		(net "M_D_CPU0_SA_DQ<14>")
	)
	(arc
		(start 341.55126 -276.219158)
		(mid 341.364062 -276.269301)
		(end 341.176864 -276.219158)
		(width 0.088646)
		(layer "In11.Cu")
		(net "M_D_CPU0_SA_DQ<14>")
	)
	(arc
		(start 341.162132 -276.210522)
		(mid 340.885657 -276.143202)
		(end 340.61146 -276.219158)
		(width 0.088646)
		(layer "In11.Cu")
		(net "M_D_CPU0_SA_DQ<14>")
	)
	(arc
		(start 347.19006 -276.219158)
		(mid 347.002862 -276.269301)
		(end 346.815664 -276.219158)
		(width 0.088646)
		(layer "In11.Cu")
		(net "M_D_CPU0_SA_DQ<14>")
	)
	(arc
		(start 346.25026 -276.219158)
		(mid 346.063062 -276.269301)
		(end 345.875864 -276.219158)
		(width 0.088646)
		(layer "In11.Cu")
		(net "M_D_CPU0_SA_DQ<14>")
	)
	(arc
		(start 343.981532 -276.210522)
		(mid 343.705057 -276.143202)
		(end 343.43086 -276.219158)
		(width 0.088646)
		(layer "In11.Cu")
		(net "M_D_CPU0_SA_DQ<14>")
	)
	(arc
		(start 334.50276 -277.032974)
		(mid 334.315562 -277.083117)
		(end 334.128364 -277.032974)
		(width 0.088646)
		(layer "In11.Cu")
		(net "M_D_CPU0_SA_DQ<14>")
	)
	(arc
		(start 334.128364 -277.032974)
		(mid 333.991891 -276.97634)
		(end 333.845408 -276.957028)
		(width 0.088646)
		(layer "In11.Cu")
		(net "M_D_CPU0_SA_DQ<14>")
	)
	(arc
		(start 342.491314 -276.219158)
		(mid 342.304116 -276.269301)
		(end 342.116918 -276.219158)
		(width 0.088646)
		(layer "In11.Cu")
		(net "M_D_CPU0_SA_DQ<14>")
	)
	(arc
		(start 338.73186 -276.219158)
		(mid 338.544662 -276.269301)
		(end 338.357464 -276.219158)
		(width 0.088646)
		(layer "In11.Cu")
		(net "M_D_CPU0_SA_DQ<14>")
	)
	(arc
		(start 344.37066 -276.219158)
		(mid 344.183462 -276.269301)
		(end 343.996264 -276.219158)
		(width 0.088646)
		(layer "In11.Cu")
		(net "M_D_CPU0_SA_DQ<14>")
	)
	(arc
		(start 336.46745 -276.213062)
		(mid 336.189018 -276.143216)
		(end 335.912206 -276.219158)
		(width 0.088646)
		(layer "In11.Cu")
		(net "M_D_CPU0_SA_DQ<14>")
	)
	(arc
		(start 334.972406 -276.219158)
		(mid 334.769583 -276.419389)
		(end 334.690212 -276.693122)
		(width 0.088646)
		(layer "In11.Cu")
		(net "M_D_CPU0_SA_DQ<14>")
	)
	(arc
		(start 344.921332 -276.210522)
		(mid 344.644857 -276.143202)
		(end 344.37066 -276.219158)
		(width 0.088646)
		(layer "In11.Cu")
		(net "M_D_CPU0_SA_DQ<14>")
	)
	(arc
		(start 340.222332 -276.210522)
		(mid 339.945857 -276.143202)
		(end 339.67166 -276.219158)
		(width 0.088646)
		(layer "In11.Cu")
		(net "M_D_CPU0_SA_DQ<14>")
	)
	(arc
		(start 337.79206 -276.219158)
		(mid 337.604862 -276.269301)
		(end 337.417664 -276.219158)
		(width 0.088646)
		(layer "In11.Cu")
		(net "M_D_CPU0_SA_DQ<14>")
	)
	(arc
		(start 346.800932 -276.210522)
		(mid 346.524457 -276.143202)
		(end 346.25026 -276.219158)
		(width 0.088646)
		(layer "In11.Cu")
		(net "M_D_CPU0_SA_DQ<14>")
	)
	(arc
		(start 345.31046 -276.219158)
		(mid 345.123262 -276.269301)
		(end 344.936064 -276.219158)
		(width 0.088646)
		(layer "In11.Cu")
		(net "M_D_CPU0_SA_DQ<14>")
	)
	(arc
		(start 343.43086 -276.219158)
		(mid 343.243662 -276.269301)
		(end 343.056464 -276.219158)
		(width 0.088646)
		(layer "In11.Cu")
		(net "M_D_CPU0_SA_DQ<14>")
	)
	(arc
		(start 342.106504 -276.213062)
		(mid 341.828072 -276.143216)
		(end 341.55126 -276.219158)
		(width 0.088646)
		(layer "In11.Cu")
		(net "M_D_CPU0_SA_DQ<14>")
	)
	(arc
		(start 334.690212 -276.708616)
		(mid 334.642533 -276.891516)
		(end 334.51165 -277.027894)
		(width 0.088646)
		(layer "In11.Cu")
		(net "M_D_CPU0_SA_DQ<14>")
	)
	(segment
		(start 264.729214 -299.316648)
		(end 263.624314 -299.316648)
		(width 0.20066)
		(layer "F.Cu")
		(net "M_D_CPU0_SA_DQ<13>")
	)
	(segment
		(start 258.130548 -299.527976)
		(end 257.626104 -299.527976)
		(width 0.20066)
		(layer "F.Cu")
		(net "M_D_CPU0_SA_DQ<13>")
	)
	(segment
		(start 261.984998 -299.316648)
		(end 261.560056 -298.891706)
		(width 0.20066)
		(layer "F.Cu")
		(net "M_D_CPU0_SA_DQ<13>")
	)
	(segment
		(start 258.44754 -298.882816)
		(end 258.28498 -299.045376)
		(width 0.20066)
		(layer "F.Cu")
		(net "M_D_CPU0_SA_DQ<13>")
	)
	(segment
		(start 257.626104 -299.527976)
		(end 257.414776 -299.316648)
		(width 0.20066)
		(layer "F.Cu")
		(net "M_D_CPU0_SA_DQ<13>")
	)
	(segment
		(start 263.624314 -299.316648)
		(end 261.984998 -299.316648)
		(width 0.20066)
		(layer "F.Cu")
		(net "M_D_CPU0_SA_DQ<13>")
	)
	(segment
		(start 261.381494 -298.891706)
		(end 261.050786 -298.891706)
		(width 0.101854)
		(layer "F.Cu")
		(net "M_D_CPU0_SA_DQ<13>")
	)
	(segment
		(start 261.560056 -298.891706)
		(end 261.381494 -298.891706)
		(width 0.20066)
		(layer "F.Cu")
		(net "M_D_CPU0_SA_DQ<13>")
	)
	(segment
		(start 258.28498 -299.373544)
		(end 258.130548 -299.527976)
		(width 0.20066)
		(layer "F.Cu")
		(net "M_D_CPU0_SA_DQ<13>")
	)
	(segment
		(start 259.065268 -298.891706)
		(end 259.056378 -298.882816)
		(width 0.1016)
		(layer "F.Cu")
		(net "M_D_CPU0_SA_DQ<13>")
	)
	(segment
		(start 259.056378 -298.882816)
		(end 258.44754 -298.882816)
		(width 0.20066)
		(layer "F.Cu")
		(net "M_D_CPU0_SA_DQ<13>")
	)
	(segment
		(start 258.28498 -299.045376)
		(end 258.28498 -299.373544)
		(width 0.20066)
		(layer "F.Cu")
		(net "M_D_CPU0_SA_DQ<13>")
	)
	(segment
		(start 261.050786 -298.891706)
		(end 259.065268 -298.891706)
		(width 0.1016)
		(layer "F.Cu")
		(net "M_D_CPU0_SA_DQ<13>")
	)
	(segment
		(start 257.414776 -299.316648)
		(end 256.080514 -299.316648)
		(width 0.20066)
		(layer "F.Cu")
		(net "M_D_CPU0_SA_DQ<13>")
	)
	(arc
		(start 347.003116 -275.35886)
		(mid 347.003052 -275.62683)
		(end 347.002862 -275.8948)
		(width 0.20066)
		(layer "F.Cu")
		(net "M_D_CPU0_SA_DQ<13>")
	)
	(segment
		(start 269.470886 -299.742352)
		(end 268.528038 -299.742352)
		(width 0.18288)
		(layer "In11.Cu")
		(net "M_D_CPU0_SA_DQ<13>")
	)
	(segment
		(start 273.456654 -301.469806)
		(end 272.666714 -300.679866)
		(width 0.18288)
		(layer "In11.Cu")
		(net "M_D_CPU0_SA_DQ<13>")
	)
	(segment
		(start 266.703048 -299.901864)
		(end 266.510008 -300.094904)
		(width 0.18288)
		(layer "In11.Cu")
		(net "M_D_CPU0_SA_DQ<13>")
	)
	(segment
		(start 330.161646 -279.27935)
		(end 318.365124 -291.075872)
		(width 0.18288)
		(layer "In11.Cu")
		(net "M_D_CPU0_SA_DQ<13>")
	)
	(segment
		(start 295.707562 -304.216054)
		(end 295.707562 -304.64887)
		(width 0.18288)
		(layer "In11.Cu")
		(net "M_D_CPU0_SA_DQ<13>")
	)
	(segment
		(start 310.736234 -297.007026)
		(end 310.494934 -297.248326)
		(width 0.18288)
		(layer "In11.Cu")
		(net "M_D_CPU0_SA_DQ<13>")
	)
	(segment
		(start 267.211048 -300.094904)
		(end 267.018008 -299.901864)
		(width 0.18288)
		(layer "In11.Cu")
		(net "M_D_CPU0_SA_DQ<13>")
	)
	(segment
		(start 265.615928 -299.901864)
		(end 265.31443 -299.901864)
		(width 0.18288)
		(layer "In11.Cu")
		(net "M_D_CPU0_SA_DQ<13>")
	)
	(segment
		(start 272.666714 -300.679866)
		(end 271.899634 -300.679866)
		(width 0.18288)
		(layer "In11.Cu")
		(net "M_D_CPU0_SA_DQ<13>")
	)
	(segment
		(start 343.996264 -275.570442)
		(end 343.981532 -275.579078)
		(width 0.088646)
		(layer "In11.Cu")
		(net "M_D_CPU0_SA_DQ<13>")
	)
	(segment
		(start 285.794958 -304.162206)
		(end 285.601918 -303.969166)
		(width 0.18288)
		(layer "In11.Cu")
		(net "M_D_CPU0_SA_DQ<13>")
	)
	(segment
		(start 266.316968 -300.50359)
		(end 266.002008 -300.50359)
		(width 0.18288)
		(layer "In11.Cu")
		(net "M_D_CPU0_SA_DQ<13>")
	)
	(segment
		(start 302.199294 -300.690026)
		(end 300.319694 -302.569626)
		(width 0.18288)
		(layer "In11.Cu")
		(net "M_D_CPU0_SA_DQ<13>")
	)
	(segment
		(start 274.84959 -301.469806)
		(end 273.456654 -301.469806)
		(width 0.18288)
		(layer "In11.Cu")
		(net "M_D_CPU0_SA_DQ<13>")
	)
	(segment
		(start 331.385926 -278.921464)
		(end 331.216254 -279.091136)
		(width 0.088646)
		(layer "In11.Cu")
		(net "M_D_CPU0_SA_DQ<13>")
	)
	(segment
		(start 279.250394 -304.84191)
		(end 278.07031 -303.661826)
		(width 0.18288)
		(layer "In11.Cu")
		(net "M_D_CPU0_SA_DQ<13>")
	)
	(segment
		(start 284.642814 -303.793906)
		(end 284.444694 -303.992026)
		(width 0.18288)
		(layer "In11.Cu")
		(net "M_D_CPU0_SA_DQ<13>")
	)
	(segment
		(start 277.243794 -303.661826)
		(end 276.608794 -303.026826)
		(width 0.18288)
		(layer "In11.Cu")
		(net "M_D_CPU0_SA_DQ<13>")
	)
	(segment
		(start 267.710412 -300.86808)
		(end 267.404088 -300.86808)
		(width 0.18288)
		(layer "In11.Cu")
		(net "M_D_CPU0_SA_DQ<13>")
	)
	(segment
		(start 265.31443 -299.901864)
		(end 264.729214 -299.316648)
		(width 0.18288)
		(layer "In11.Cu")
		(net "M_D_CPU0_SA_DQ<13>")
	)
	(segment
		(start 307.068474 -298.287186)
		(end 306.085494 -298.287186)
		(width 0.18288)
		(layer "In11.Cu")
		(net "M_D_CPU0_SA_DQ<13>")
	)
	(segment
		(start 341.176864 -275.570442)
		(end 341.162132 -275.579078)
		(width 0.088646)
		(layer "In11.Cu")
		(net "M_D_CPU0_SA_DQ<13>")
	)
	(segment
		(start 296.408602 -304.216054)
		(end 296.215562 -304.023014)
		(width 0.18288)
		(layer "In11.Cu")
		(net "M_D_CPU0_SA_DQ<13>")
	)
	(segment
		(start 265.808968 -300.094904)
		(end 265.615928 -299.901864)
		(width 0.18288)
		(layer "In11.Cu")
		(net "M_D_CPU0_SA_DQ<13>")
	)
	(segment
		(start 333.177896 -277.021036)
		(end 333.177896 -277.315676)
		(width 0.088646)
		(layer "In11.Cu")
		(net "M_D_CPU0_SA_DQ<13>")
	)
	(segment
		(start 268.528038 -299.742352)
		(end 268.368526 -299.901864)
		(width 0.18288)
		(layer "In11.Cu")
		(net "M_D_CPU0_SA_DQ<13>")
	)
	(segment
		(start 331.02804 -279.27935)
		(end 330.161646 -279.27935)
		(width 0.18288)
		(layer "In11.Cu")
		(net "M_D_CPU0_SA_DQ<13>")
	)
	(segment
		(start 306.085494 -298.287186)
		(end 304.419254 -299.953426)
		(width 0.18288)
		(layer "In11.Cu")
		(net "M_D_CPU0_SA_DQ<13>")
	)
	(segment
		(start 285.008574 -303.793906)
		(end 284.642814 -303.793906)
		(width 0.18288)
		(layer "In11.Cu")
		(net "M_D_CPU0_SA_DQ<13>")
	)
	(segment
		(start 284.444694 -303.992026)
		(end 283.282644 -303.992026)
		(width 0.18288)
		(layer "In11.Cu")
		(net "M_D_CPU0_SA_DQ<13>")
	)
	(segment
		(start 285.601918 -303.969166)
		(end 285.183834 -303.969166)
		(width 0.18288)
		(layer "In11.Cu")
		(net "M_D_CPU0_SA_DQ<13>")
	)
	(segment
		(start 270.855186 -299.635418)
		(end 269.57782 -299.635418)
		(width 0.18288)
		(layer "In11.Cu")
		(net "M_D_CPU0_SA_DQ<13>")
	)
	(segment
		(start 289.356292 -304.456846)
		(end 289.010852 -304.111406)
		(width 0.18288)
		(layer "In11.Cu")
		(net "M_D_CPU0_SA_DQ<13>")
	)
	(segment
		(start 285.794958 -304.316384)
		(end 285.794958 -304.162206)
		(width 0.18288)
		(layer "In11.Cu")
		(net "M_D_CPU0_SA_DQ<13>")
	)
	(segment
		(start 286.495998 -304.316384)
		(end 286.302958 -304.509424)
		(width 0.18288)
		(layer "In11.Cu")
		(net "M_D_CPU0_SA_DQ<13>")
	)
	(segment
		(start 268.105128 -299.901864)
		(end 267.912088 -300.094904)
		(width 0.18288)
		(layer "In11.Cu")
		(net "M_D_CPU0_SA_DQ<13>")
	)
	(segment
		(start 286.302958 -304.509424)
		(end 285.987998 -304.509424)
		(width 0.18288)
		(layer "In11.Cu")
		(net "M_D_CPU0_SA_DQ<13>")
	)
	(segment
		(start 281.168094 -304.068226)
		(end 280.39441 -304.84191)
		(width 0.18288)
		(layer "In11.Cu")
		(net "M_D_CPU0_SA_DQ<13>")
	)
	(segment
		(start 318.365124 -291.075872)
		(end 318.365124 -291.721286)
		(width 0.18288)
		(layer "In11.Cu")
		(net "M_D_CPU0_SA_DQ<13>")
	)
	(segment
		(start 269.57782 -299.635418)
		(end 269.470886 -299.742352)
		(width 0.18288)
		(layer "In11.Cu")
		(net "M_D_CPU0_SA_DQ<13>")
	)
	(segment
		(start 283.282644 -303.992026)
		(end 283.206444 -304.068226)
		(width 0.18288)
		(layer "In11.Cu")
		(net "M_D_CPU0_SA_DQ<13>")
	)
	(segment
		(start 285.183834 -303.969166)
		(end 285.008574 -303.793906)
		(width 0.18288)
		(layer "In11.Cu")
		(net "M_D_CPU0_SA_DQ<13>")
	)
	(segment
		(start 296.527982 -304.713386)
		(end 296.408602 -304.594006)
		(width 0.18288)
		(layer "In11.Cu")
		(net "M_D_CPU0_SA_DQ<13>")
	)
	(segment
		(start 280.39441 -304.84191)
		(end 279.250394 -304.84191)
		(width 0.18288)
		(layer "In11.Cu")
		(net "M_D_CPU0_SA_DQ<13>")
	)
	(segment
		(start 343.056464 -275.570442)
		(end 343.04605 -275.576538)
		(width 0.088646)
		(layer "In11.Cu")
		(net "M_D_CPU0_SA_DQ<13>")
	)
	(segment
		(start 267.912088 -300.666404)
		(end 267.710412 -300.86808)
		(width 0.18288)
		(layer "In11.Cu")
		(net "M_D_CPU0_SA_DQ<13>")
	)
	(segment
		(start 283.206444 -304.068226)
		(end 281.168094 -304.068226)
		(width 0.18288)
		(layer "In11.Cu")
		(net "M_D_CPU0_SA_DQ<13>")
	)
	(segment
		(start 333.177896 -277.315676)
		(end 331.572108 -278.921464)
		(width 0.088646)
		(layer "In11.Cu")
		(net "M_D_CPU0_SA_DQ<13>")
	)
	(segment
		(start 295.900602 -304.023014)
		(end 295.707562 -304.216054)
		(width 0.18288)
		(layer "In11.Cu")
		(net "M_D_CPU0_SA_DQ<13>")
	)
	(segment
		(start 290.057332 -304.111406)
		(end 289.711892 -304.456846)
		(width 0.18288)
		(layer "In11.Cu")
		(net "M_D_CPU0_SA_DQ<13>")
	)
	(segment
		(start 293.28237 -303.951386)
		(end 292.054534 -303.951386)
		(width 0.18288)
		(layer "In11.Cu")
		(net "M_D_CPU0_SA_DQ<13>")
	)
	(segment
		(start 334.410558 -275.8948)
		(end 334.410558 -275.910294)
		(width 0.088646)
		(layer "In11.Cu")
		(net "M_D_CPU0_SA_DQ<13>")
	)
	(segment
		(start 345.875864 -275.570442)
		(end 345.861132 -275.579078)
		(width 0.088646)
		(layer "In11.Cu")
		(net "M_D_CPU0_SA_DQ<13>")
	)
	(segment
		(start 278.07031 -303.661826)
		(end 277.243794 -303.661826)
		(width 0.18288)
		(layer "In11.Cu")
		(net "M_D_CPU0_SA_DQ<13>")
	)
	(segment
		(start 266.510008 -300.094904)
		(end 266.510008 -300.31055)
		(width 0.18288)
		(layer "In11.Cu")
		(net "M_D_CPU0_SA_DQ<13>")
	)
	(segment
		(start 289.010852 -304.111406)
		(end 288.628582 -304.111406)
		(width 0.18288)
		(layer "In11.Cu")
		(net "M_D_CPU0_SA_DQ<13>")
	)
	(segment
		(start 339.297264 -275.570442)
		(end 339.282532 -275.579078)
		(width 0.088646)
		(layer "In11.Cu")
		(net "M_D_CPU0_SA_DQ<13>")
	)
	(segment
		(start 267.912088 -300.094904)
		(end 267.912088 -300.666404)
		(width 0.18288)
		(layer "In11.Cu")
		(net "M_D_CPU0_SA_DQ<13>")
	)
	(segment
		(start 266.002008 -300.50359)
		(end 265.808968 -300.31055)
		(width 0.18288)
		(layer "In11.Cu")
		(net "M_D_CPU0_SA_DQ<13>")
	)
	(segment
		(start 318.365124 -291.721286)
		(end 314.6171 -295.46931)
		(width 0.18288)
		(layer "In11.Cu")
		(net "M_D_CPU0_SA_DQ<13>")
	)
	(segment
		(start 267.018008 -299.901864)
		(end 266.703048 -299.901864)
		(width 0.18288)
		(layer "In11.Cu")
		(net "M_D_CPU0_SA_DQ<13>")
	)
	(segment
		(start 331.216254 -279.091136)
		(end 331.02804 -279.27935)
		(width 0.18288)
		(layer "In11.Cu")
		(net "M_D_CPU0_SA_DQ<13>")
	)
	(segment
		(start 300.319694 -303.077626)
		(end 299.405294 -303.992026)
		(width 0.18288)
		(layer "In11.Cu")
		(net "M_D_CPU0_SA_DQ<13>")
	)
	(segment
		(start 314.42406 -296.397426)
		(end 313.232038 -296.397426)
		(width 0.18288)
		(layer "In11.Cu")
		(net "M_D_CPU0_SA_DQ<13>")
	)
	(segment
		(start 313.232038 -296.397426)
		(end 312.622438 -297.007026)
		(width 0.18288)
		(layer "In11.Cu")
		(net "M_D_CPU0_SA_DQ<13>")
	)
	(segment
		(start 265.808968 -300.31055)
		(end 265.808968 -300.094904)
		(width 0.18288)
		(layer "In11.Cu")
		(net "M_D_CPU0_SA_DQ<13>")
	)
	(segment
		(start 308.368954 -297.944286)
		(end 307.411374 -297.944286)
		(width 0.18288)
		(layer "In11.Cu")
		(net "M_D_CPU0_SA_DQ<13>")
	)
	(segment
		(start 314.6171 -295.46931)
		(end 314.6171 -296.204386)
		(width 0.18288)
		(layer "In11.Cu")
		(net "M_D_CPU0_SA_DQ<13>")
	)
	(segment
		(start 347.002862 -275.8948)
		(end 347.315536 -275.8948)
		(width 0.088646)
		(layer "In11.Cu")
		(net "M_D_CPU0_SA_DQ<13>")
	)
	(segment
		(start 331.572108 -278.921464)
		(end 331.385926 -278.921464)
		(width 0.088646)
		(layer "In11.Cu")
		(net "M_D_CPU0_SA_DQ<13>")
	)
	(segment
		(start 309.064914 -297.248326)
		(end 308.368954 -297.944286)
		(width 0.18288)
		(layer "In11.Cu")
		(net "M_D_CPU0_SA_DQ<13>")
	)
	(segment
		(start 298.615354 -303.992026)
		(end 297.893994 -304.713386)
		(width 0.18288)
		(layer "In11.Cu")
		(net "M_D_CPU0_SA_DQ<13>")
	)
	(segment
		(start 271.899634 -300.679866)
		(end 270.855186 -299.635418)
		(width 0.18288)
		(layer "In11.Cu")
		(net "M_D_CPU0_SA_DQ<13>")
	)
	(segment
		(start 307.411374 -297.944286)
		(end 307.068474 -298.287186)
		(width 0.18288)
		(layer "In11.Cu")
		(net "M_D_CPU0_SA_DQ<13>")
	)
	(segment
		(start 304.419254 -299.953426)
		(end 303.705514 -299.953426)
		(width 0.18288)
		(layer "In11.Cu")
		(net "M_D_CPU0_SA_DQ<13>")
	)
	(segment
		(start 310.494934 -297.248326)
		(end 309.064914 -297.248326)
		(width 0.18288)
		(layer "In11.Cu")
		(net "M_D_CPU0_SA_DQ<13>")
	)
	(segment
		(start 296.215562 -304.023014)
		(end 295.900602 -304.023014)
		(width 0.18288)
		(layer "In11.Cu")
		(net "M_D_CPU0_SA_DQ<13>")
	)
	(segment
		(start 267.404088 -300.86808)
		(end 267.211048 -300.67504)
		(width 0.18288)
		(layer "In11.Cu")
		(net "M_D_CPU0_SA_DQ<13>")
	)
	(segment
		(start 297.893994 -304.713386)
		(end 296.527982 -304.713386)
		(width 0.18288)
		(layer "In11.Cu")
		(net "M_D_CPU0_SA_DQ<13>")
	)
	(segment
		(start 266.510008 -300.31055)
		(end 266.316968 -300.50359)
		(width 0.18288)
		(layer "In11.Cu")
		(net "M_D_CPU0_SA_DQ<13>")
	)
	(segment
		(start 288.486342 -303.969166)
		(end 286.689038 -303.969166)
		(width 0.18288)
		(layer "In11.Cu")
		(net "M_D_CPU0_SA_DQ<13>")
	)
	(segment
		(start 286.495998 -304.162206)
		(end 286.495998 -304.316384)
		(width 0.18288)
		(layer "In11.Cu")
		(net "M_D_CPU0_SA_DQ<13>")
	)
	(segment
		(start 334.59801 -275.570442)
		(end 334.58912 -275.575522)
		(width 0.088646)
		(layer "In11.Cu")
		(net "M_D_CPU0_SA_DQ<13>")
	)
	(segment
		(start 347.315536 -275.8948)
		(end 347.37294 -275.837396)
		(width 0.088646)
		(layer "In11.Cu")
		(net "M_D_CPU0_SA_DQ<13>")
	)
	(segment
		(start 295.707562 -304.64887)
		(end 295.514522 -304.84191)
		(width 0.18288)
		(layer "In11.Cu")
		(net "M_D_CPU0_SA_DQ<13>")
	)
	(segment
		(start 344.936064 -275.570442)
		(end 344.921332 -275.579078)
		(width 0.088646)
		(layer "In11.Cu")
		(net "M_D_CPU0_SA_DQ<13>")
	)
	(segment
		(start 267.211048 -300.67504)
		(end 267.211048 -300.094904)
		(width 0.18288)
		(layer "In11.Cu")
		(net "M_D_CPU0_SA_DQ<13>")
	)
	(segment
		(start 347.19895 -275.575522)
		(end 347.19006 -275.570442)
		(width 0.088646)
		(layer "In11.Cu")
		(net "M_D_CPU0_SA_DQ<13>")
	)
	(segment
		(start 300.319694 -302.569626)
		(end 300.319694 -303.077626)
		(width 0.18288)
		(layer "In11.Cu")
		(net "M_D_CPU0_SA_DQ<13>")
	)
	(segment
		(start 291.894514 -304.111406)
		(end 290.057332 -304.111406)
		(width 0.18288)
		(layer "In11.Cu")
		(net "M_D_CPU0_SA_DQ<13>")
	)
	(segment
		(start 276.40661 -303.026826)
		(end 274.84959 -301.469806)
		(width 0.18288)
		(layer "In11.Cu")
		(net "M_D_CPU0_SA_DQ<13>")
	)
	(segment
		(start 286.689038 -303.969166)
		(end 286.495998 -304.162206)
		(width 0.18288)
		(layer "In11.Cu")
		(net "M_D_CPU0_SA_DQ<13>")
	)
	(segment
		(start 296.408602 -304.594006)
		(end 296.408602 -304.216054)
		(width 0.18288)
		(layer "In11.Cu")
		(net "M_D_CPU0_SA_DQ<13>")
	)
	(segment
		(start 312.622438 -297.007026)
		(end 310.736234 -297.007026)
		(width 0.18288)
		(layer "In11.Cu")
		(net "M_D_CPU0_SA_DQ<13>")
	)
	(segment
		(start 295.514522 -304.84191)
		(end 294.172894 -304.84191)
		(width 0.18288)
		(layer "In11.Cu")
		(net "M_D_CPU0_SA_DQ<13>")
	)
	(segment
		(start 342.116918 -275.570442)
		(end 342.106504 -275.576538)
		(width 0.088646)
		(layer "In11.Cu")
		(net "M_D_CPU0_SA_DQ<13>")
	)
	(segment
		(start 336.477864 -275.570442)
		(end 336.46745 -275.576538)
		(width 0.088646)
		(layer "In11.Cu")
		(net "M_D_CPU0_SA_DQ<13>")
	)
	(segment
		(start 285.987998 -304.509424)
		(end 285.794958 -304.316384)
		(width 0.18288)
		(layer "In11.Cu")
		(net "M_D_CPU0_SA_DQ<13>")
	)
	(segment
		(start 289.711892 -304.456846)
		(end 289.356292 -304.456846)
		(width 0.18288)
		(layer "In11.Cu")
		(net "M_D_CPU0_SA_DQ<13>")
	)
	(segment
		(start 299.405294 -303.992026)
		(end 298.615354 -303.992026)
		(width 0.18288)
		(layer "In11.Cu")
		(net "M_D_CPU0_SA_DQ<13>")
	)
	(segment
		(start 292.054534 -303.951386)
		(end 291.894514 -304.111406)
		(width 0.18288)
		(layer "In11.Cu")
		(net "M_D_CPU0_SA_DQ<13>")
	)
	(segment
		(start 288.628582 -304.111406)
		(end 288.486342 -303.969166)
		(width 0.18288)
		(layer "In11.Cu")
		(net "M_D_CPU0_SA_DQ<13>")
	)
	(segment
		(start 276.608794 -303.026826)
		(end 276.40661 -303.026826)
		(width 0.18288)
		(layer "In11.Cu")
		(net "M_D_CPU0_SA_DQ<13>")
	)
	(segment
		(start 294.172894 -304.84191)
		(end 293.28237 -303.951386)
		(width 0.18288)
		(layer "In11.Cu")
		(net "M_D_CPU0_SA_DQ<13>")
	)
	(segment
		(start 268.368526 -299.901864)
		(end 268.105128 -299.901864)
		(width 0.18288)
		(layer "In11.Cu")
		(net "M_D_CPU0_SA_DQ<13>")
	)
	(segment
		(start 302.968914 -300.690026)
		(end 302.199294 -300.690026)
		(width 0.18288)
		(layer "In11.Cu")
		(net "M_D_CPU0_SA_DQ<13>")
	)
	(segment
		(start 314.6171 -296.204386)
		(end 314.42406 -296.397426)
		(width 0.18288)
		(layer "In11.Cu")
		(net "M_D_CPU0_SA_DQ<13>")
	)
	(segment
		(start 303.705514 -299.953426)
		(end 302.968914 -300.690026)
		(width 0.18288)
		(layer "In11.Cu")
		(net "M_D_CPU0_SA_DQ<13>")
	)
	(arc
		(start 341.162132 -275.579078)
		(mid 340.885691 -275.646244)
		(end 340.61146 -275.570442)
		(width 0.088646)
		(layer "In11.Cu")
		(net "M_D_CPU0_SA_DQ<13>")
	)
	(arc
		(start 337.417664 -275.570442)
		(mid 337.134962 -275.646184)
		(end 336.85226 -275.570442)
		(width 0.088646)
		(layer "In11.Cu")
		(net "M_D_CPU0_SA_DQ<13>")
	)
	(arc
		(start 339.282532 -275.579078)
		(mid 339.006091 -275.646244)
		(end 338.73186 -275.570442)
		(width 0.088646)
		(layer "In11.Cu")
		(net "M_D_CPU0_SA_DQ<13>")
	)
	(arc
		(start 347.19006 -275.570442)
		(mid 347.002862 -275.520299)
		(end 346.815664 -275.570442)
		(width 0.088646)
		(layer "In11.Cu")
		(net "M_D_CPU0_SA_DQ<13>")
	)
	(arc
		(start 338.357464 -275.570442)
		(mid 338.074762 -275.646184)
		(end 337.79206 -275.570442)
		(width 0.088646)
		(layer "In11.Cu")
		(net "M_D_CPU0_SA_DQ<13>")
	)
	(arc
		(start 334.58912 -275.575522)
		(mid 334.458206 -275.711882)
		(end 334.410558 -275.8948)
		(width 0.088646)
		(layer "In11.Cu")
		(net "M_D_CPU0_SA_DQ<13>")
	)
	(arc
		(start 345.861132 -275.579078)
		(mid 345.584691 -275.646244)
		(end 345.31046 -275.570442)
		(width 0.088646)
		(layer "In11.Cu")
		(net "M_D_CPU0_SA_DQ<13>")
	)
	(arc
		(start 343.43086 -275.570442)
		(mid 343.243662 -275.520299)
		(end 343.056464 -275.570442)
		(width 0.088646)
		(layer "In11.Cu")
		(net "M_D_CPU0_SA_DQ<13>")
	)
	(arc
		(start 336.85226 -275.570442)
		(mid 336.665062 -275.520299)
		(end 336.477864 -275.570442)
		(width 0.088646)
		(layer "In11.Cu")
		(net "M_D_CPU0_SA_DQ<13>")
	)
	(arc
		(start 335.53781 -275.570442)
		(mid 335.255108 -275.646184)
		(end 334.972406 -275.570442)
		(width 0.088646)
		(layer "In11.Cu")
		(net "M_D_CPU0_SA_DQ<13>")
	)
	(arc
		(start 338.73186 -275.570442)
		(mid 338.544662 -275.520299)
		(end 338.357464 -275.570442)
		(width 0.088646)
		(layer "In11.Cu")
		(net "M_D_CPU0_SA_DQ<13>")
	)
	(arc
		(start 334.410558 -275.910294)
		(mid 334.331188 -276.184028)
		(end 334.128364 -276.384258)
		(width 0.088646)
		(layer "In11.Cu")
		(net "M_D_CPU0_SA_DQ<13>")
	)
	(arc
		(start 334.128364 -276.384258)
		(mid 333.96696 -276.447117)
		(end 333.7941 -276.458172)
		(width 0.088646)
		(layer "In11.Cu")
		(net "M_D_CPU0_SA_DQ<13>")
	)
	(arc
		(start 347.37294 -275.837396)
		(mid 347.314784 -275.687283)
		(end 347.19895 -275.575522)
		(width 0.088646)
		(layer "In11.Cu")
		(net "M_D_CPU0_SA_DQ<13>")
	)
	(arc
		(start 336.46745 -275.576538)
		(mid 336.189018 -275.646352)
		(end 335.912206 -275.570442)
		(width 0.088646)
		(layer "In11.Cu")
		(net "M_D_CPU0_SA_DQ<13>")
	)
	(arc
		(start 345.31046 -275.570442)
		(mid 345.123262 -275.520299)
		(end 344.936064 -275.570442)
		(width 0.088646)
		(layer "In11.Cu")
		(net "M_D_CPU0_SA_DQ<13>")
	)
	(arc
		(start 334.972406 -275.570442)
		(mid 334.785208 -275.520299)
		(end 334.59801 -275.570442)
		(width 0.088646)
		(layer "In11.Cu")
		(net "M_D_CPU0_SA_DQ<13>")
	)
	(arc
		(start 342.491314 -275.570442)
		(mid 342.304116 -275.520299)
		(end 342.116918 -275.570442)
		(width 0.088646)
		(layer "In11.Cu")
		(net "M_D_CPU0_SA_DQ<13>")
	)
	(arc
		(start 343.981532 -275.579078)
		(mid 343.705091 -275.646244)
		(end 343.43086 -275.570442)
		(width 0.088646)
		(layer "In11.Cu")
		(net "M_D_CPU0_SA_DQ<13>")
	)
	(arc
		(start 342.106504 -275.576538)
		(mid 341.828072 -275.646352)
		(end 341.55126 -275.570442)
		(width 0.088646)
		(layer "In11.Cu")
		(net "M_D_CPU0_SA_DQ<13>")
	)
	(arc
		(start 333.7941 -276.458172)
		(mid 333.361885 -276.603737)
		(end 333.177896 -277.021036)
		(width 0.088646)
		(layer "In11.Cu")
		(net "M_D_CPU0_SA_DQ<13>")
	)
	(arc
		(start 341.55126 -275.570442)
		(mid 341.364062 -275.520299)
		(end 341.176864 -275.570442)
		(width 0.088646)
		(layer "In11.Cu")
		(net "M_D_CPU0_SA_DQ<13>")
	)
	(arc
		(start 339.67166 -275.570442)
		(mid 339.484462 -275.520299)
		(end 339.297264 -275.570442)
		(width 0.088646)
		(layer "In11.Cu")
		(net "M_D_CPU0_SA_DQ<13>")
	)
	(arc
		(start 344.37066 -275.570442)
		(mid 344.183462 -275.520299)
		(end 343.996264 -275.570442)
		(width 0.088646)
		(layer "In11.Cu")
		(net "M_D_CPU0_SA_DQ<13>")
	)
	(arc
		(start 344.921332 -275.579078)
		(mid 344.644891 -275.646244)
		(end 344.37066 -275.570442)
		(width 0.088646)
		(layer "In11.Cu")
		(net "M_D_CPU0_SA_DQ<13>")
	)
	(arc
		(start 346.25026 -275.570442)
		(mid 346.063062 -275.520299)
		(end 345.875864 -275.570442)
		(width 0.088646)
		(layer "In11.Cu")
		(net "M_D_CPU0_SA_DQ<13>")
	)
	(arc
		(start 340.237064 -275.570442)
		(mid 339.954362 -275.646184)
		(end 339.67166 -275.570442)
		(width 0.088646)
		(layer "In11.Cu")
		(net "M_D_CPU0_SA_DQ<13>")
	)
	(arc
		(start 346.815664 -275.570442)
		(mid 346.532962 -275.646184)
		(end 346.25026 -275.570442)
		(width 0.088646)
		(layer "In11.Cu")
		(net "M_D_CPU0_SA_DQ<13>")
	)
	(arc
		(start 343.04605 -275.576538)
		(mid 342.767872 -275.64623)
		(end 342.491314 -275.570442)
		(width 0.088646)
		(layer "In11.Cu")
		(net "M_D_CPU0_SA_DQ<13>")
	)
	(arc
		(start 340.61146 -275.570442)
		(mid 340.424262 -275.520299)
		(end 340.237064 -275.570442)
		(width 0.088646)
		(layer "In11.Cu")
		(net "M_D_CPU0_SA_DQ<13>")
	)
	(arc
		(start 337.79206 -275.570442)
		(mid 337.604862 -275.520299)
		(end 337.417664 -275.570442)
		(width 0.088646)
		(layer "In11.Cu")
		(net "M_D_CPU0_SA_DQ<13>")
	)
	(arc
		(start 335.912206 -275.570442)
		(mid 335.725008 -275.520299)
		(end 335.53781 -275.570442)
		(width 0.088646)
		(layer "In11.Cu")
		(net "M_D_CPU0_SA_DQ<13>")
	)
	(segment
		(start 261.830312 -300.591728)
		(end 261.381494 -300.591728)
		(width 0.20066)
		(layer "F.Cu")
		(net "M_D_CPU0_SA_DQ<12>")
	)
	(segment
		(start 258.28498 -300.79315)
		(end 258.28498 -301.08271)
		(width 0.20066)
		(layer "F.Cu")
		(net "M_D_CPU0_SA_DQ<12>")
	)
	(segment
		(start 257.653536 -301.25543)
		(end 257.414776 -301.01667)
		(width 0.20066)
		(layer "F.Cu")
		(net "M_D_CPU0_SA_DQ<12>")
	)
	(segment
		(start 259.056378 -300.5836)
		(end 258.49453 -300.5836)
		(width 0.20066)
		(layer "F.Cu")
		(net "M_D_CPU0_SA_DQ<12>")
	)
	(segment
		(start 346.532962 -276.172676)
		(end 346.532962 -276.708362)
		(width 0.20066)
		(layer "F.Cu")
		(net "M_D_CPU0_SA_DQ<12>")
	)
	(segment
		(start 258.11226 -301.25543)
		(end 257.653536 -301.25543)
		(width 0.20066)
		(layer "F.Cu")
		(net "M_D_CPU0_SA_DQ<12>")
	)
	(segment
		(start 258.28498 -301.08271)
		(end 258.11226 -301.25543)
		(width 0.20066)
		(layer "F.Cu")
		(net "M_D_CPU0_SA_DQ<12>")
	)
	(segment
		(start 259.064506 -300.591728)
		(end 259.056378 -300.5836)
		(width 0.101854)
		(layer "F.Cu")
		(net "M_D_CPU0_SA_DQ<12>")
	)
	(segment
		(start 263.624314 -301.01667)
		(end 262.255254 -301.01667)
		(width 0.20066)
		(layer "F.Cu")
		(net "M_D_CPU0_SA_DQ<12>")
	)
	(segment
		(start 257.414776 -301.01667)
		(end 256.080514 -301.01667)
		(width 0.20066)
		(layer "F.Cu")
		(net "M_D_CPU0_SA_DQ<12>")
	)
	(segment
		(start 261.381494 -300.591728)
		(end 259.31241 -300.591728)
		(width 0.1016)
		(layer "F.Cu")
		(net "M_D_CPU0_SA_DQ<12>")
	)
	(segment
		(start 259.31241 -300.591728)
		(end 259.064506 -300.591728)
		(width 0.101854)
		(layer "F.Cu")
		(net "M_D_CPU0_SA_DQ<12>")
	)
	(segment
		(start 264.729214 -301.01667)
		(end 263.624314 -301.01667)
		(width 0.20066)
		(layer "F.Cu")
		(net "M_D_CPU0_SA_DQ<12>")
	)
	(segment
		(start 258.49453 -300.5836)
		(end 258.28498 -300.79315)
		(width 0.20066)
		(layer "F.Cu")
		(net "M_D_CPU0_SA_DQ<12>")
	)
	(segment
		(start 262.255254 -301.01667)
		(end 261.830312 -300.591728)
		(width 0.20066)
		(layer "F.Cu")
		(net "M_D_CPU0_SA_DQ<12>")
	)
	(segment
		(start 346.532962 -276.708362)
		(end 346.533216 -276.708616)
		(width 0.20066)
		(layer "F.Cu")
		(net "M_D_CPU0_SA_DQ<12>")
	)
	(segment
		(start 275.805138 -304.677826)
		(end 275.198078 -304.070766)
		(width 0.18288)
		(layer "In11.Cu")
		(net "M_D_CPU0_SA_DQ<12>")
	)
	(segment
		(start 288.356294 -306.354226)
		(end 287.629092 -305.627024)
		(width 0.18288)
		(layer "In11.Cu")
		(net "M_D_CPU0_SA_DQ<12>")
	)
	(segment
		(start 332.25867 -278.861012)
		(end 332.25867 -279.505156)
		(width 0.088646)
		(layer "In11.Cu")
		(net "M_D_CPU0_SA_DQ<12>")
	)
	(segment
		(start 266.553188 -302.267874)
		(end 266.360148 -302.460914)
		(width 0.18288)
		(layer "In11.Cu")
		(net "M_D_CPU0_SA_DQ<12>")
	)
	(segment
		(start 343.915746 -276.392894)
		(end 343.901014 -276.384258)
		(width 0.088646)
		(layer "In11.Cu")
		(net "M_D_CPU0_SA_DQ<12>")
	)
	(segment
		(start 267.447268 -302.460914)
		(end 267.254228 -302.267874)
		(width 0.18288)
		(layer "In11.Cu")
		(net "M_D_CPU0_SA_DQ<12>")
	)
	(segment
		(start 270.273526 -301.302166)
		(end 269.612872 -301.302166)
		(width 0.18288)
		(layer "In11.Cu")
		(net "M_D_CPU0_SA_DQ<12>")
	)
	(segment
		(start 268.35227 -301.639986)
		(end 268.148308 -301.639986)
		(width 0.18288)
		(layer "In11.Cu")
		(net "M_D_CPU0_SA_DQ<12>")
	)
	(segment
		(start 332.25867 -279.505156)
		(end 331.944472 -279.819354)
		(width 0.088646)
		(layer "In11.Cu")
		(net "M_D_CPU0_SA_DQ<12>")
	)
	(segment
		(start 342.975946 -276.392894)
		(end 342.961214 -276.384258)
		(width 0.088646)
		(layer "In11.Cu")
		(net "M_D_CPU0_SA_DQ<12>")
	)
	(segment
		(start 333.590392 -277.260304)
		(end 333.590392 -277.52929)
		(width 0.088646)
		(layer "In11.Cu")
		(net "M_D_CPU0_SA_DQ<12>")
	)
	(segment
		(start 298.642786 -305.69154)
		(end 298.0817 -306.252626)
		(width 0.18288)
		(layer "In11.Cu")
		(net "M_D_CPU0_SA_DQ<12>")
	)
	(segment
		(start 276.888194 -305.11877)
		(end 276.44725 -304.677826)
		(width 0.18288)
		(layer "In11.Cu")
		(net "M_D_CPU0_SA_DQ<12>")
	)
	(segment
		(start 283.55163 -305.69154)
		(end 283.346144 -305.897026)
		(width 0.18288)
		(layer "In11.Cu")
		(net "M_D_CPU0_SA_DQ<12>")
	)
	(segment
		(start 281.374596 -306.541424)
		(end 279.550622 -306.541424)
		(width 0.18288)
		(layer "In11.Cu")
		(net "M_D_CPU0_SA_DQ<12>")
	)
	(segment
		(start 290.740592 -306.547266)
		(end 290.740592 -306.859686)
		(width 0.18288)
		(layer "In11.Cu")
		(net "M_D_CPU0_SA_DQ<12>")
	)
	(segment
		(start 269.612872 -301.302166)
		(end 269.472664 -301.442374)
		(width 0.18288)
		(layer "In11.Cu")
		(net "M_D_CPU0_SA_DQ<12>")
	)
	(segment
		(start 267.061188 -301.639986)
		(end 266.746228 -301.639986)
		(width 0.18288)
		(layer "In11.Cu")
		(net "M_D_CPU0_SA_DQ<12>")
	)
	(segment
		(start 290.039552 -306.547266)
		(end 289.846512 -306.354226)
		(width 0.18288)
		(layer "In11.Cu")
		(net "M_D_CPU0_SA_DQ<12>")
	)
	(segment
		(start 315.6458 -295.964102)
		(end 315.6458 -296.84853)
		(width 0.18288)
		(layer "In11.Cu")
		(net "M_D_CPU0_SA_DQ<12>")
	)
	(segment
		(start 330.496164 -280.382218)
		(end 319.381124 -291.497258)
		(width 0.18288)
		(layer "In11.Cu")
		(net "M_D_CPU0_SA_DQ<12>")
	)
	(segment
		(start 266.746228 -301.639986)
		(end 266.553188 -301.833026)
		(width 0.18288)
		(layer "In11.Cu")
		(net "M_D_CPU0_SA_DQ<12>")
	)
	(segment
		(start 284.81401 -305.627024)
		(end 284.749494 -305.69154)
		(width 0.18288)
		(layer "In11.Cu")
		(net "M_D_CPU0_SA_DQ<12>")
	)
	(segment
		(start 309.072026 -298.892214)
		(end 308.368954 -299.595286)
		(width 0.18288)
		(layer "In11.Cu")
		(net "M_D_CPU0_SA_DQ<12>")
	)
	(segment
		(start 334.880712 -276.708616)
		(end 334.880712 -276.72284)
		(width 0.088646)
		(layer "In11.Cu")
		(net "M_D_CPU0_SA_DQ<12>")
	)
	(segment
		(start 335.068164 -276.384258)
		(end 335.059274 -276.389338)
		(width 0.088646)
		(layer "In11.Cu")
		(net "M_D_CPU0_SA_DQ<12>")
	)
	(segment
		(start 287.629092 -305.627024)
		(end 284.81401 -305.627024)
		(width 0.18288)
		(layer "In11.Cu")
		(net "M_D_CPU0_SA_DQ<12>")
	)
	(segment
		(start 283.346144 -305.897026)
		(end 282.018994 -305.897026)
		(width 0.18288)
		(layer "In11.Cu")
		(net "M_D_CPU0_SA_DQ<12>")
	)
	(segment
		(start 331.944472 -279.819354)
		(end 331.381608 -280.382218)
		(width 0.18288)
		(layer "In11.Cu")
		(net "M_D_CPU0_SA_DQ<12>")
	)
	(segment
		(start 346.533216 -276.708616)
		(end 346.473526 -276.648926)
		(width 0.088646)
		(layer "In11.Cu")
		(net "M_D_CPU0_SA_DQ<12>")
	)
	(segment
		(start 290.232592 -307.052726)
		(end 290.039552 -306.859686)
		(width 0.18288)
		(layer "In11.Cu")
		(net "M_D_CPU0_SA_DQ<12>")
	)
	(segment
		(start 311.008776 -298.892214)
		(end 309.072026 -298.892214)
		(width 0.18288)
		(layer "In11.Cu")
		(net "M_D_CPU0_SA_DQ<12>")
	)
	(segment
		(start 275.198078 -303.49571)
		(end 274.729194 -303.026826)
		(width 0.18288)
		(layer "In11.Cu")
		(net "M_D_CPU0_SA_DQ<12>")
	)
	(segment
		(start 279.550622 -306.541424)
		(end 279.30602 -306.786026)
		(width 0.18288)
		(layer "In11.Cu")
		(net "M_D_CPU0_SA_DQ<12>")
	)
	(segment
		(start 297.425872 -306.252626)
		(end 297.301412 -306.377086)
		(width 0.18288)
		(layer "In11.Cu")
		(net "M_D_CPU0_SA_DQ<12>")
	)
	(segment
		(start 333.845154 -277.147274)
		(end 333.703422 -277.147274)
		(width 0.088646)
		(layer "In11.Cu")
		(net "M_D_CPU0_SA_DQ<12>")
	)
	(segment
		(start 265.852148 -302.267874)
		(end 265.852148 -301.833026)
		(width 0.18288)
		(layer "In11.Cu")
		(net "M_D_CPU0_SA_DQ<12>")
	)
	(segment
		(start 289.846512 -306.354226)
		(end 288.356294 -306.354226)
		(width 0.18288)
		(layer "In11.Cu")
		(net "M_D_CPU0_SA_DQ<12>")
	)
	(segment
		(start 295.750234 -306.377086)
		(end 295.585896 -306.541424)
		(width 0.18288)
		(layer "In11.Cu")
		(net "M_D_CPU0_SA_DQ<12>")
	)
	(segment
		(start 300.51756 -305.59756)
		(end 299.410374 -305.59756)
		(width 0.18288)
		(layer "In11.Cu")
		(net "M_D_CPU0_SA_DQ<12>")
	)
	(segment
		(start 273.588988 -303.026826)
		(end 270.872966 -301.901606)
		(width 0.18288)
		(layer "In11.Cu")
		(net "M_D_CPU0_SA_DQ<12>")
	)
	(segment
		(start 333.590392 -277.52929)
		(end 332.25867 -278.861012)
		(width 0.088646)
		(layer "In11.Cu")
		(net "M_D_CPU0_SA_DQ<12>")
	)
	(segment
		(start 319.381124 -292.228778)
		(end 315.6458 -295.964102)
		(width 0.18288)
		(layer "In11.Cu")
		(net "M_D_CPU0_SA_DQ<12>")
	)
	(segment
		(start 277.205694 -306.786026)
		(end 276.888194 -306.468526)
		(width 0.18288)
		(layer "In11.Cu")
		(net "M_D_CPU0_SA_DQ<12>")
	)
	(segment
		(start 312.504074 -298.698666)
		(end 311.202324 -298.698666)
		(width 0.18288)
		(layer "In11.Cu")
		(net "M_D_CPU0_SA_DQ<12>")
	)
	(segment
		(start 266.360148 -302.460914)
		(end 266.045188 -302.460914)
		(width 0.18288)
		(layer "In11.Cu")
		(net "M_D_CPU0_SA_DQ<12>")
	)
	(segment
		(start 290.740592 -306.859686)
		(end 290.547552 -307.052726)
		(width 0.18288)
		(layer "In11.Cu")
		(net "M_D_CPU0_SA_DQ<12>")
	)
	(segment
		(start 340.156546 -276.392894)
		(end 340.141814 -276.384258)
		(width 0.088646)
		(layer "In11.Cu")
		(net "M_D_CPU0_SA_DQ<12>")
	)
	(segment
		(start 319.381124 -291.497258)
		(end 319.381124 -292.228778)
		(width 0.18288)
		(layer "In11.Cu")
		(net "M_D_CPU0_SA_DQ<12>")
	)
	(segment
		(start 292.54069 -305.643026)
		(end 291.82949 -306.354226)
		(width 0.18288)
		(layer "In11.Cu")
		(net "M_D_CPU0_SA_DQ<12>")
	)
	(segment
		(start 268.549882 -301.442374)
		(end 268.35227 -301.639986)
		(width 0.18288)
		(layer "In11.Cu")
		(net "M_D_CPU0_SA_DQ<12>")
	)
	(segment
		(start 266.045188 -302.460914)
		(end 265.852148 -302.267874)
		(width 0.18288)
		(layer "In11.Cu")
		(net "M_D_CPU0_SA_DQ<12>")
	)
	(segment
		(start 333.703422 -277.147274)
		(end 333.590392 -277.260304)
		(width 0.088646)
		(layer "In11.Cu")
		(net "M_D_CPU0_SA_DQ<12>")
	)
	(segment
		(start 267.254228 -301.833026)
		(end 267.061188 -301.639986)
		(width 0.18288)
		(layer "In11.Cu")
		(net "M_D_CPU0_SA_DQ<12>")
	)
	(segment
		(start 344.851228 -276.390354)
		(end 344.840814 -276.384258)
		(width 0.088646)
		(layer "In11.Cu")
		(net "M_D_CPU0_SA_DQ<12>")
	)
	(segment
		(start 345.790774 -276.390354)
		(end 345.78036 -276.384258)
		(width 0.088646)
		(layer "In11.Cu")
		(net "M_D_CPU0_SA_DQ<12>")
	)
	(segment
		(start 279.30602 -306.786026)
		(end 277.205694 -306.786026)
		(width 0.18288)
		(layer "In11.Cu")
		(net "M_D_CPU0_SA_DQ<12>")
	)
	(segment
		(start 295.585896 -306.541424)
		(end 294.004492 -306.541424)
		(width 0.18288)
		(layer "In11.Cu")
		(net "M_D_CPU0_SA_DQ<12>")
	)
	(segment
		(start 284.749494 -305.69154)
		(end 283.55163 -305.69154)
		(width 0.18288)
		(layer "In11.Cu")
		(net "M_D_CPU0_SA_DQ<12>")
	)
	(segment
		(start 282.018994 -305.897026)
		(end 281.374596 -306.541424)
		(width 0.18288)
		(layer "In11.Cu")
		(net "M_D_CPU0_SA_DQ<12>")
	)
	(segment
		(start 274.729194 -303.026826)
		(end 273.588988 -303.026826)
		(width 0.18288)
		(layer "In11.Cu")
		(net "M_D_CPU0_SA_DQ<12>")
	)
	(segment
		(start 306.156614 -300.499526)
		(end 305.615594 -300.499526)
		(width 0.18288)
		(layer "In11.Cu")
		(net "M_D_CPU0_SA_DQ<12>")
	)
	(segment
		(start 341.096346 -276.392894)
		(end 341.081614 -276.384258)
		(width 0.088646)
		(layer "In11.Cu")
		(net "M_D_CPU0_SA_DQ<12>")
	)
	(segment
		(start 334.59801 -277.198328)
		(end 334.583278 -277.206964)
		(width 0.088646)
		(layer "In11.Cu")
		(net "M_D_CPU0_SA_DQ<12>")
	)
	(segment
		(start 290.039552 -306.859686)
		(end 290.039552 -306.547266)
		(width 0.18288)
		(layer "In11.Cu")
		(net "M_D_CPU0_SA_DQ<12>")
	)
	(segment
		(start 298.0817 -306.252626)
		(end 297.425872 -306.252626)
		(width 0.18288)
		(layer "In11.Cu")
		(net "M_D_CPU0_SA_DQ<12>")
	)
	(segment
		(start 268.148308 -301.639986)
		(end 267.955268 -301.833026)
		(width 0.18288)
		(layer "In11.Cu")
		(net "M_D_CPU0_SA_DQ<12>")
	)
	(segment
		(start 299.316394 -305.69154)
		(end 298.642786 -305.69154)
		(width 0.18288)
		(layer "In11.Cu")
		(net "M_D_CPU0_SA_DQ<12>")
	)
	(segment
		(start 299.410374 -305.59756)
		(end 299.316394 -305.69154)
		(width 0.18288)
		(layer "In11.Cu")
		(net "M_D_CPU0_SA_DQ<12>")
	)
	(segment
		(start 269.472664 -301.442374)
		(end 268.549882 -301.442374)
		(width 0.18288)
		(layer "In11.Cu")
		(net "M_D_CPU0_SA_DQ<12>")
	)
	(segment
		(start 331.381608 -280.382218)
		(end 330.496164 -280.382218)
		(width 0.18288)
		(layer "In11.Cu")
		(net "M_D_CPU0_SA_DQ<12>")
	)
	(segment
		(start 314.452254 -298.042076)
		(end 313.160664 -298.042076)
		(width 0.18288)
		(layer "In11.Cu")
		(net "M_D_CPU0_SA_DQ<12>")
	)
	(segment
		(start 290.547552 -307.052726)
		(end 290.232592 -307.052726)
		(width 0.18288)
		(layer "In11.Cu")
		(net "M_D_CPU0_SA_DQ<12>")
	)
	(segment
		(start 276.888194 -306.468526)
		(end 276.888194 -305.11877)
		(width 0.18288)
		(layer "In11.Cu")
		(net "M_D_CPU0_SA_DQ<12>")
	)
	(segment
		(start 267.955268 -302.267874)
		(end 267.762228 -302.460914)
		(width 0.18288)
		(layer "In11.Cu")
		(net "M_D_CPU0_SA_DQ<12>")
	)
	(segment
		(start 315.6458 -296.84853)
		(end 314.452254 -298.042076)
		(width 0.18288)
		(layer "In11.Cu")
		(net "M_D_CPU0_SA_DQ<12>")
	)
	(segment
		(start 270.872966 -301.901606)
		(end 270.273526 -301.302166)
		(width 0.18288)
		(layer "In11.Cu")
		(net "M_D_CPU0_SA_DQ<12>")
	)
	(segment
		(start 275.198078 -304.070766)
		(end 275.198078 -303.49571)
		(width 0.18288)
		(layer "In11.Cu")
		(net "M_D_CPU0_SA_DQ<12>")
	)
	(segment
		(start 307.060854 -299.595286)
		(end 306.156614 -300.499526)
		(width 0.18288)
		(layer "In11.Cu")
		(net "M_D_CPU0_SA_DQ<12>")
	)
	(segment
		(start 311.202324 -298.698666)
		(end 311.008776 -298.892214)
		(width 0.18288)
		(layer "In11.Cu")
		(net "M_D_CPU0_SA_DQ<12>")
	)
	(segment
		(start 266.553188 -301.833026)
		(end 266.553188 -302.267874)
		(width 0.18288)
		(layer "In11.Cu")
		(net "M_D_CPU0_SA_DQ<12>")
	)
	(segment
		(start 313.160664 -298.042076)
		(end 312.504074 -298.698666)
		(width 0.18288)
		(layer "In11.Cu")
		(net "M_D_CPU0_SA_DQ<12>")
	)
	(segment
		(start 265.852148 -301.833026)
		(end 265.659108 -301.639986)
		(width 0.18288)
		(layer "In11.Cu")
		(net "M_D_CPU0_SA_DQ<12>")
	)
	(segment
		(start 294.004492 -306.541424)
		(end 293.106094 -305.643026)
		(width 0.18288)
		(layer "In11.Cu")
		(net "M_D_CPU0_SA_DQ<12>")
	)
	(segment
		(start 339.212174 -276.390354)
		(end 339.20176 -276.384258)
		(width 0.088646)
		(layer "In11.Cu")
		(net "M_D_CPU0_SA_DQ<12>")
	)
	(segment
		(start 297.301412 -306.377086)
		(end 295.750234 -306.377086)
		(width 0.18288)
		(layer "In11.Cu")
		(net "M_D_CPU0_SA_DQ<12>")
	)
	(segment
		(start 276.44725 -304.677826)
		(end 275.805138 -304.677826)
		(width 0.18288)
		(layer "In11.Cu")
		(net "M_D_CPU0_SA_DQ<12>")
	)
	(segment
		(start 267.955268 -301.833026)
		(end 267.955268 -302.267874)
		(width 0.18288)
		(layer "In11.Cu")
		(net "M_D_CPU0_SA_DQ<12>")
	)
	(segment
		(start 267.254228 -302.267874)
		(end 267.254228 -301.833026)
		(width 0.18288)
		(layer "In11.Cu")
		(net "M_D_CPU0_SA_DQ<12>")
	)
	(segment
		(start 267.762228 -302.460914)
		(end 267.447268 -302.460914)
		(width 0.18288)
		(layer "In11.Cu")
		(net "M_D_CPU0_SA_DQ<12>")
	)
	(segment
		(start 305.615594 -300.499526)
		(end 300.51756 -305.59756)
		(width 0.18288)
		(layer "In11.Cu")
		(net "M_D_CPU0_SA_DQ<12>")
	)
	(segment
		(start 308.368954 -299.595286)
		(end 307.060854 -299.595286)
		(width 0.18288)
		(layer "In11.Cu")
		(net "M_D_CPU0_SA_DQ<12>")
	)
	(segment
		(start 290.933632 -306.354226)
		(end 290.740592 -306.547266)
		(width 0.18288)
		(layer "In11.Cu")
		(net "M_D_CPU0_SA_DQ<12>")
	)
	(segment
		(start 293.106094 -305.643026)
		(end 292.54069 -305.643026)
		(width 0.18288)
		(layer "In11.Cu")
		(net "M_D_CPU0_SA_DQ<12>")
	)
	(segment
		(start 291.82949 -306.354226)
		(end 290.933632 -306.354226)
		(width 0.18288)
		(layer "In11.Cu")
		(net "M_D_CPU0_SA_DQ<12>")
	)
	(segment
		(start 265.35253 -301.639986)
		(end 264.729214 -301.01667)
		(width 0.18288)
		(layer "In11.Cu")
		(net "M_D_CPU0_SA_DQ<12>")
	)
	(segment
		(start 265.659108 -301.639986)
		(end 265.35253 -301.639986)
		(width 0.18288)
		(layer "In11.Cu")
		(net "M_D_CPU0_SA_DQ<12>")
	)
	(segment
		(start 335.457292 -276.392894)
		(end 335.44256 -276.384258)
		(width 0.088646)
		(layer "In11.Cu")
		(net "M_D_CPU0_SA_DQ<12>")
	)
	(arc
		(start 341.081614 -276.384258)
		(mid 340.894416 -276.334115)
		(end 340.707218 -276.384258)
		(width 0.088646)
		(layer "In11.Cu")
		(net "M_D_CPU0_SA_DQ<12>")
	)
	(arc
		(start 340.707218 -276.384258)
		(mid 340.433019 -276.460093)
		(end 340.156546 -276.392894)
		(width 0.088646)
		(layer "In11.Cu")
		(net "M_D_CPU0_SA_DQ<12>")
	)
	(arc
		(start 344.840814 -276.384258)
		(mid 344.653616 -276.334115)
		(end 344.466418 -276.384258)
		(width 0.088646)
		(layer "In11.Cu")
		(net "M_D_CPU0_SA_DQ<12>")
	)
	(arc
		(start 345.78036 -276.384258)
		(mid 345.593162 -276.334115)
		(end 345.405964 -276.384258)
		(width 0.088646)
		(layer "In11.Cu")
		(net "M_D_CPU0_SA_DQ<12>")
	)
	(arc
		(start 337.32216 -276.384258)
		(mid 337.134962 -276.334115)
		(end 336.947764 -276.384258)
		(width 0.088646)
		(layer "In11.Cu")
		(net "M_D_CPU0_SA_DQ<12>")
	)
	(arc
		(start 334.583278 -277.206964)
		(mid 334.306837 -277.27413)
		(end 334.032606 -277.198328)
		(width 0.088646)
		(layer "In11.Cu")
		(net "M_D_CPU0_SA_DQ<12>")
	)
	(arc
		(start 342.586818 -276.384258)
		(mid 342.304116 -276.460034)
		(end 342.021414 -276.384258)
		(width 0.088646)
		(layer "In11.Cu")
		(net "M_D_CPU0_SA_DQ<12>")
	)
	(arc
		(start 339.20176 -276.384258)
		(mid 339.014562 -276.334115)
		(end 338.827364 -276.384258)
		(width 0.088646)
		(layer "In11.Cu")
		(net "M_D_CPU0_SA_DQ<12>")
	)
	(arc
		(start 336.007964 -276.384258)
		(mid 335.733765 -276.460093)
		(end 335.457292 -276.392894)
		(width 0.088646)
		(layer "In11.Cu")
		(net "M_D_CPU0_SA_DQ<12>")
	)
	(arc
		(start 337.887564 -276.384258)
		(mid 337.604862 -276.460034)
		(end 337.32216 -276.384258)
		(width 0.088646)
		(layer "In11.Cu")
		(net "M_D_CPU0_SA_DQ<12>")
	)
	(arc
		(start 343.526618 -276.384258)
		(mid 343.252419 -276.460093)
		(end 342.975946 -276.392894)
		(width 0.088646)
		(layer "In11.Cu")
		(net "M_D_CPU0_SA_DQ<12>")
	)
	(arc
		(start 346.473526 -276.648926)
		(mid 346.274984 -276.513431)
		(end 346.04071 -276.459696)
		(width 0.088646)
		(layer "In11.Cu")
		(net "M_D_CPU0_SA_DQ<12>")
	)
	(arc
		(start 344.466418 -276.384258)
		(mid 344.192219 -276.460093)
		(end 343.915746 -276.392894)
		(width 0.088646)
		(layer "In11.Cu")
		(net "M_D_CPU0_SA_DQ<12>")
	)
	(arc
		(start 343.901014 -276.384258)
		(mid 343.713816 -276.334115)
		(end 343.526618 -276.384258)
		(width 0.088646)
		(layer "In11.Cu")
		(net "M_D_CPU0_SA_DQ<12>")
	)
	(arc
		(start 336.947764 -276.384258)
		(mid 336.665062 -276.460034)
		(end 336.38236 -276.384258)
		(width 0.088646)
		(layer "In11.Cu")
		(net "M_D_CPU0_SA_DQ<12>")
	)
	(arc
		(start 342.021414 -276.384258)
		(mid 341.834216 -276.334115)
		(end 341.647018 -276.384258)
		(width 0.088646)
		(layer "In11.Cu")
		(net "M_D_CPU0_SA_DQ<12>")
	)
	(arc
		(start 334.880712 -276.72284)
		(mid 334.801493 -276.997525)
		(end 334.59801 -277.198328)
		(width 0.088646)
		(layer "In11.Cu")
		(net "M_D_CPU0_SA_DQ<12>")
	)
	(arc
		(start 339.767418 -276.384258)
		(mid 339.490605 -276.460128)
		(end 339.212174 -276.390354)
		(width 0.088646)
		(layer "In11.Cu")
		(net "M_D_CPU0_SA_DQ<12>")
	)
	(arc
		(start 342.961214 -276.384258)
		(mid 342.774016 -276.334115)
		(end 342.586818 -276.384258)
		(width 0.088646)
		(layer "In11.Cu")
		(net "M_D_CPU0_SA_DQ<12>")
	)
	(arc
		(start 334.032606 -277.198328)
		(mid 333.942248 -277.160425)
		(end 333.845154 -277.147274)
		(width 0.088646)
		(layer "In11.Cu")
		(net "M_D_CPU0_SA_DQ<12>")
	)
	(arc
		(start 335.44256 -276.384258)
		(mid 335.255362 -276.334115)
		(end 335.068164 -276.384258)
		(width 0.088646)
		(layer "In11.Cu")
		(net "M_D_CPU0_SA_DQ<12>")
	)
	(arc
		(start 335.059274 -276.389338)
		(mid 334.92836 -276.525698)
		(end 334.880712 -276.708616)
		(width 0.088646)
		(layer "In11.Cu")
		(net "M_D_CPU0_SA_DQ<12>")
	)
	(arc
		(start 345.405964 -276.384258)
		(mid 345.129405 -276.460001)
		(end 344.851228 -276.390354)
		(width 0.088646)
		(layer "In11.Cu")
		(net "M_D_CPU0_SA_DQ<12>")
	)
	(arc
		(start 338.827364 -276.384258)
		(mid 338.544662 -276.460034)
		(end 338.26196 -276.384258)
		(width 0.088646)
		(layer "In11.Cu")
		(net "M_D_CPU0_SA_DQ<12>")
	)
	(arc
		(start 336.38236 -276.384258)
		(mid 336.195162 -276.334115)
		(end 336.007964 -276.384258)
		(width 0.088646)
		(layer "In11.Cu")
		(net "M_D_CPU0_SA_DQ<12>")
	)
	(arc
		(start 346.04071 -276.459696)
		(mid 345.911708 -276.439561)
		(end 345.790774 -276.390354)
		(width 0.088646)
		(layer "In11.Cu")
		(net "M_D_CPU0_SA_DQ<12>")
	)
	(arc
		(start 341.647018 -276.384258)
		(mid 341.372819 -276.460093)
		(end 341.096346 -276.392894)
		(width 0.088646)
		(layer "In11.Cu")
		(net "M_D_CPU0_SA_DQ<12>")
	)
	(arc
		(start 340.141814 -276.384258)
		(mid 339.954616 -276.334115)
		(end 339.767418 -276.384258)
		(width 0.088646)
		(layer "In11.Cu")
		(net "M_D_CPU0_SA_DQ<12>")
	)
	(arc
		(start 338.26196 -276.384258)
		(mid 338.074762 -276.334115)
		(end 337.887564 -276.384258)
		(width 0.088646)
		(layer "In11.Cu")
		(net "M_D_CPU0_SA_DQ<12>")
	)
	(segment
		(start 262.514334 -304.841656)
		(end 262.50011 -304.85588)
		(width 0.101854)
		(layer "F.Cu")
		(net "M_D_CPU0_SA_DQ<11>")
	)
	(segment
		(start 348.412562 -278.336248)
		(end 348.412816 -278.336502)
		(width 0.20066)
		(layer "F.Cu")
		(net "M_D_CPU0_SA_DQ<11>")
	)
	(segment
		(start 262.003794 -304.542698)
		(end 261.87781 -304.416714)
		(width 0.20066)
		(layer "F.Cu")
		(net "M_D_CPU0_SA_DQ<11>")
	)
	(segment
		(start 262.50011 -304.85588)
		(end 262.146288 -304.85588)
		(width 0.20066)
		(layer "F.Cu")
		(net "M_D_CPU0_SA_DQ<11>")
	)
	(segment
		(start 265.369548 -304.841656)
		(end 264.825226 -304.841656)
		(width 0.20066)
		(layer "F.Cu")
		(net "M_D_CPU0_SA_DQ<11>")
	)
	(segment
		(start 265.518646 -304.692558)
		(end 265.369548 -304.841656)
		(width 0.20066)
		(layer "F.Cu")
		(net "M_D_CPU0_SA_DQ<11>")
	)
	(segment
		(start 265.518646 -304.54092)
		(end 265.518646 -304.692558)
		(width 0.20066)
		(layer "F.Cu")
		(net "M_D_CPU0_SA_DQ<11>")
	)
	(segment
		(start 266.700762 -304.624232)
		(end 266.25423 -304.624232)
		(width 0.20066)
		(layer "F.Cu")
		(net "M_D_CPU0_SA_DQ<11>")
	)
	(segment
		(start 262.752332 -304.841656)
		(end 262.514334 -304.841656)
		(width 0.101854)
		(layer "F.Cu")
		(net "M_D_CPU0_SA_DQ<11>")
	)
	(segment
		(start 266.90828 -304.416714)
		(end 266.700762 -304.624232)
		(width 0.20066)
		(layer "F.Cu")
		(net "M_D_CPU0_SA_DQ<11>")
	)
	(segment
		(start 262.003794 -304.713386)
		(end 262.003794 -304.542698)
		(width 0.20066)
		(layer "F.Cu")
		(net "M_D_CPU0_SA_DQ<11>")
	)
	(segment
		(start 266.25423 -304.624232)
		(end 266.042394 -304.412396)
		(width 0.20066)
		(layer "F.Cu")
		(net "M_D_CPU0_SA_DQ<11>")
	)
	(segment
		(start 265.64717 -304.412396)
		(end 265.518646 -304.54092)
		(width 0.20066)
		(layer "F.Cu")
		(net "M_D_CPU0_SA_DQ<11>")
	)
	(segment
		(start 267.724382 -304.416714)
		(end 266.90828 -304.416714)
		(width 0.20066)
		(layer "F.Cu")
		(net "M_D_CPU0_SA_DQ<11>")
	)
	(segment
		(start 348.412562 -277.800562)
		(end 348.412562 -278.336248)
		(width 0.20066)
		(layer "F.Cu")
		(net "M_D_CPU0_SA_DQ<11>")
	)
	(segment
		(start 266.042394 -304.412396)
		(end 265.64717 -304.412396)
		(width 0.20066)
		(layer "F.Cu")
		(net "M_D_CPU0_SA_DQ<11>")
	)
	(segment
		(start 261.87781 -304.416714)
		(end 260.180582 -304.416714)
		(width 0.20066)
		(layer "F.Cu")
		(net "M_D_CPU0_SA_DQ<11>")
	)
	(segment
		(start 264.825226 -304.841656)
		(end 262.752332 -304.841656)
		(width 0.1016)
		(layer "F.Cu")
		(net "M_D_CPU0_SA_DQ<11>")
	)
	(segment
		(start 262.146288 -304.85588)
		(end 262.003794 -304.713386)
		(width 0.20066)
		(layer "F.Cu")
		(net "M_D_CPU0_SA_DQ<11>")
	)
	(segment
		(start 268.829282 -304.416714)
		(end 267.724382 -304.416714)
		(width 0.20066)
		(layer "F.Cu")
		(net "M_D_CPU0_SA_DQ<11>")
	)
	(segment
		(start 346.346018 -278.012144)
		(end 346.060014 -278.177498)
		(width 0.088646)
		(layer "In11.Cu")
		(net "M_D_CPU0_SA_DQ<11>")
	)
	(segment
		(start 333.57185 -280.283412)
		(end 333.56296 -280.288492)
		(width 0.088646)
		(layer "In11.Cu")
		(net "M_D_CPU0_SA_DQ<11>")
	)
	(segment
		(start 333.280512 -281.495246)
		(end 331.915516 -282.860242)
		(width 0.088646)
		(layer "In11.Cu")
		(net "M_D_CPU0_SA_DQ<11>")
	)
	(segment
		(start 331.915516 -282.860242)
		(end 331.709522 -282.860242)
		(width 0.088646)
		(layer "In11.Cu")
		(net "M_D_CPU0_SA_DQ<11>")
	)
	(segment
		(start 288.026856 -310.059324)
		(end 284.51683 -310.059324)
		(width 0.18288)
		(layer "In11.Cu")
		(net "M_D_CPU0_SA_DQ<11>")
	)
	(segment
		(start 331.131926 -282.860242)
		(end 321.672204 -292.319964)
		(width 0.18288)
		(layer "In11.Cu")
		(net "M_D_CPU0_SA_DQ<11>")
	)
	(segment
		(start 271.739614 -305.891184)
		(end 270.853154 -305.004724)
		(width 0.18288)
		(layer "In11.Cu")
		(net "M_D_CPU0_SA_DQ<11>")
	)
	(segment
		(start 347.689424 -278.029162)
		(end 347.660214 -278.012144)
		(width 0.088646)
		(layer "In11.Cu")
		(net "M_D_CPU0_SA_DQ<11>")
	)
	(segment
		(start 305.902614 -306.02936)
		(end 304.404014 -307.52796)
		(width 0.18288)
		(layer "In11.Cu")
		(net "M_D_CPU0_SA_DQ<11>")
	)
	(segment
		(start 342.975946 -278.652224)
		(end 342.961214 -278.66086)
		(width 0.088646)
		(layer "In11.Cu")
		(net "M_D_CPU0_SA_DQ<11>")
	)
	(segment
		(start 348.412816 -278.336502)
		(end 347.689424 -278.029162)
		(width 0.088646)
		(layer "In11.Cu")
		(net "M_D_CPU0_SA_DQ<11>")
	)
	(segment
		(start 293.565326 -310.290464)
		(end 292.522656 -310.290464)
		(width 0.18288)
		(layer "In11.Cu")
		(net "M_D_CPU0_SA_DQ<11>")
	)
	(segment
		(start 280.315924 -310.928766)
		(end 280.179272 -310.792114)
		(width 0.18288)
		(layer "In11.Cu")
		(net "M_D_CPU0_SA_DQ<11>")
	)
	(segment
		(start 344.855546 -278.652224)
		(end 344.840814 -278.66086)
		(width 0.088646)
		(layer "In11.Cu")
		(net "M_D_CPU0_SA_DQ<11>")
	)
	(segment
		(start 300.405292 -310.078882)
		(end 299.434758 -310.078882)
		(width 0.18288)
		(layer "In11.Cu")
		(net "M_D_CPU0_SA_DQ<11>")
	)
	(segment
		(start 283.079444 -309.94223)
		(end 282.092908 -310.928766)
		(width 0.18288)
		(layer "In11.Cu")
		(net "M_D_CPU0_SA_DQ<11>")
	)
	(segment
		(start 270.853154 -305.004724)
		(end 269.417292 -305.004724)
		(width 0.18288)
		(layer "In11.Cu")
		(net "M_D_CPU0_SA_DQ<11>")
	)
	(segment
		(start 333.280512 -280.759662)
		(end 333.280512 -281.495246)
		(width 0.088646)
		(layer "In11.Cu")
		(net "M_D_CPU0_SA_DQ<11>")
	)
	(segment
		(start 346.720414 -278.012144)
		(end 346.72016 -278.012144)
		(width 0.088646)
		(layer "In11.Cu")
		(net "M_D_CPU0_SA_DQ<11>")
	)
	(segment
		(start 311.028588 -303.99101)
		(end 308.178708 -303.99101)
		(width 0.18288)
		(layer "In11.Cu")
		(net "M_D_CPU0_SA_DQ<11>")
	)
	(segment
		(start 302.118014 -308.36616)
		(end 300.405292 -310.078882)
		(width 0.18288)
		(layer "In11.Cu")
		(net "M_D_CPU0_SA_DQ<11>")
	)
	(segment
		(start 272.952972 -310.101742)
		(end 272.231612 -310.101742)
		(width 0.18288)
		(layer "In11.Cu")
		(net "M_D_CPU0_SA_DQ<11>")
	)
	(segment
		(start 312.727594 -304.127662)
		(end 311.16524 -304.127662)
		(width 0.18288)
		(layer "In11.Cu")
		(net "M_D_CPU0_SA_DQ<11>")
	)
	(segment
		(start 269.417292 -305.004724)
		(end 268.829282 -304.416714)
		(width 0.18288)
		(layer "In11.Cu")
		(net "M_D_CPU0_SA_DQ<11>")
	)
	(segment
		(start 317.879476 -296.926254)
		(end 317.879476 -299.623734)
		(width 0.18288)
		(layer "In11.Cu")
		(net "M_D_CPU0_SA_DQ<11>")
	)
	(segment
		(start 303.438814 -307.52796)
		(end 302.600614 -308.36616)
		(width 0.18288)
		(layer "In11.Cu")
		(net "M_D_CPU0_SA_DQ<11>")
	)
	(segment
		(start 278.193754 -311.675526)
		(end 277.400766 -311.675526)
		(width 0.18288)
		(layer "In11.Cu")
		(net "M_D_CPU0_SA_DQ<11>")
	)
	(segment
		(start 314.360306 -303.142904)
		(end 313.712352 -303.142904)
		(width 0.18288)
		(layer "In11.Cu")
		(net "M_D_CPU0_SA_DQ<11>")
	)
	(segment
		(start 294.066976 -310.792114)
		(end 293.565326 -310.290464)
		(width 0.18288)
		(layer "In11.Cu")
		(net "M_D_CPU0_SA_DQ<11>")
	)
	(segment
		(start 284.51683 -310.059324)
		(end 284.399736 -309.94223)
		(width 0.18288)
		(layer "In11.Cu")
		(net "M_D_CPU0_SA_DQ<11>")
	)
	(segment
		(start 311.16524 -304.127662)
		(end 311.028588 -303.99101)
		(width 0.18288)
		(layer "In11.Cu")
		(net "M_D_CPU0_SA_DQ<11>")
	)
	(segment
		(start 302.600614 -308.36616)
		(end 302.118014 -308.36616)
		(width 0.18288)
		(layer "In11.Cu")
		(net "M_D_CPU0_SA_DQ<11>")
	)
	(segment
		(start 345.780868 -278.660606)
		(end 345.780614 -278.66086)
		(width 0.088646)
		(layer "In11.Cu")
		(net "M_D_CPU0_SA_DQ<11>")
	)
	(segment
		(start 304.404014 -307.52796)
		(end 303.438814 -307.52796)
		(width 0.18288)
		(layer "In11.Cu")
		(net "M_D_CPU0_SA_DQ<11>")
	)
	(segment
		(start 284.399736 -309.94223)
		(end 283.079444 -309.94223)
		(width 0.18288)
		(layer "In11.Cu")
		(net "M_D_CPU0_SA_DQ<11>")
	)
	(segment
		(start 321.672204 -293.133526)
		(end 317.879476 -296.926254)
		(width 0.18288)
		(layer "In11.Cu")
		(net "M_D_CPU0_SA_DQ<11>")
	)
	(segment
		(start 277.400766 -311.675526)
		(end 276.80158 -311.07634)
		(width 0.18288)
		(layer "In11.Cu")
		(net "M_D_CPU0_SA_DQ<11>")
	)
	(segment
		(start 308.019958 -303.83226)
		(end 307.2257 -303.83226)
		(width 0.18288)
		(layer "In11.Cu")
		(net "M_D_CPU0_SA_DQ<11>")
	)
	(segment
		(start 346.735146 -278.02078)
		(end 346.720414 -278.012144)
		(width 0.088646)
		(layer "In11.Cu")
		(net "M_D_CPU0_SA_DQ<11>")
	)
	(segment
		(start 273.92757 -311.07634)
		(end 272.952972 -310.101742)
		(width 0.18288)
		(layer "In11.Cu")
		(net "M_D_CPU0_SA_DQ<11>")
	)
	(segment
		(start 339.212174 -278.654764)
		(end 339.20176 -278.66086)
		(width 0.088646)
		(layer "In11.Cu")
		(net "M_D_CPU0_SA_DQ<11>")
	)
	(segment
		(start 295.918382 -310.792114)
		(end 294.066976 -310.792114)
		(width 0.18288)
		(layer "In11.Cu")
		(net "M_D_CPU0_SA_DQ<11>")
	)
	(segment
		(start 307.2257 -303.83226)
		(end 305.902614 -305.155346)
		(width 0.18288)
		(layer "In11.Cu")
		(net "M_D_CPU0_SA_DQ<11>")
	)
	(segment
		(start 292.522656 -310.290464)
		(end 291.912294 -310.900826)
		(width 0.18288)
		(layer "In11.Cu")
		(net "M_D_CPU0_SA_DQ<11>")
	)
	(segment
		(start 296.103294 -310.977026)
		(end 295.918382 -310.792114)
		(width 0.18288)
		(layer "In11.Cu")
		(net "M_D_CPU0_SA_DQ<11>")
	)
	(segment
		(start 308.178708 -303.99101)
		(end 308.019958 -303.83226)
		(width 0.18288)
		(layer "In11.Cu")
		(net "M_D_CPU0_SA_DQ<11>")
	)
	(segment
		(start 272.231612 -310.101742)
		(end 271.739614 -309.609744)
		(width 0.18288)
		(layer "In11.Cu")
		(net "M_D_CPU0_SA_DQ<11>")
	)
	(segment
		(start 321.672204 -292.319964)
		(end 321.672204 -293.133526)
		(width 0.18288)
		(layer "In11.Cu")
		(net "M_D_CPU0_SA_DQ<11>")
	)
	(segment
		(start 331.709522 -282.860242)
		(end 331.131926 -282.860242)
		(width 0.18288)
		(layer "In11.Cu")
		(net "M_D_CPU0_SA_DQ<11>")
	)
	(segment
		(start 335.92135 -279.469596)
		(end 335.91246 -279.474676)
		(width 0.088646)
		(layer "In11.Cu")
		(net "M_D_CPU0_SA_DQ<11>")
	)
	(segment
		(start 343.915746 -278.652224)
		(end 343.901014 -278.66086)
		(width 0.088646)
		(layer "In11.Cu")
		(net "M_D_CPU0_SA_DQ<11>")
	)
	(segment
		(start 282.092908 -310.928766)
		(end 280.315924 -310.928766)
		(width 0.18288)
		(layer "In11.Cu")
		(net "M_D_CPU0_SA_DQ<11>")
	)
	(segment
		(start 345.780614 -278.66086)
		(end 345.78036 -278.66086)
		(width 0.088646)
		(layer "In11.Cu")
		(net "M_D_CPU0_SA_DQ<11>")
	)
	(segment
		(start 313.712352 -303.142904)
		(end 312.727594 -304.127662)
		(width 0.18288)
		(layer "In11.Cu")
		(net "M_D_CPU0_SA_DQ<11>")
	)
	(segment
		(start 317.879476 -299.623734)
		(end 314.360306 -303.142904)
		(width 0.18288)
		(layer "In11.Cu")
		(net "M_D_CPU0_SA_DQ<11>")
	)
	(segment
		(start 336.099912 -279.140412)
		(end 336.099912 -279.150318)
		(width 0.088646)
		(layer "In11.Cu")
		(net "M_D_CPU0_SA_DQ<11>")
	)
	(segment
		(start 341.096346 -278.652224)
		(end 341.081614 -278.66086)
		(width 0.088646)
		(layer "In11.Cu")
		(net "M_D_CPU0_SA_DQ<11>")
	)
	(segment
		(start 280.179272 -310.792114)
		(end 279.077166 -310.792114)
		(width 0.18288)
		(layer "In11.Cu")
		(net "M_D_CPU0_SA_DQ<11>")
	)
	(segment
		(start 340.156546 -278.652224)
		(end 340.141814 -278.66086)
		(width 0.088646)
		(layer "In11.Cu")
		(net "M_D_CPU0_SA_DQ<11>")
	)
	(segment
		(start 333.750412 -279.954228)
		(end 333.750412 -279.964134)
		(width 0.088646)
		(layer "In11.Cu")
		(net "M_D_CPU0_SA_DQ<11>")
	)
	(segment
		(start 347.660214 -278.012144)
		(end 347.65996 -278.012144)
		(width 0.088646)
		(layer "In11.Cu")
		(net "M_D_CPU0_SA_DQ<11>")
	)
	(segment
		(start 297.132248 -310.977026)
		(end 296.103294 -310.977026)
		(width 0.18288)
		(layer "In11.Cu")
		(net "M_D_CPU0_SA_DQ<11>")
	)
	(segment
		(start 271.739614 -309.609744)
		(end 271.739614 -305.891184)
		(width 0.18288)
		(layer "In11.Cu")
		(net "M_D_CPU0_SA_DQ<11>")
	)
	(segment
		(start 299.298106 -309.94223)
		(end 298.167044 -309.94223)
		(width 0.18288)
		(layer "In11.Cu")
		(net "M_D_CPU0_SA_DQ<11>")
	)
	(segment
		(start 305.902614 -305.155346)
		(end 305.902614 -306.02936)
		(width 0.18288)
		(layer "In11.Cu")
		(net "M_D_CPU0_SA_DQ<11>")
	)
	(segment
		(start 299.434758 -310.078882)
		(end 299.298106 -309.94223)
		(width 0.18288)
		(layer "In11.Cu")
		(net "M_D_CPU0_SA_DQ<11>")
	)
	(segment
		(start 298.167044 -309.94223)
		(end 297.132248 -310.977026)
		(width 0.18288)
		(layer "In11.Cu")
		(net "M_D_CPU0_SA_DQ<11>")
	)
	(segment
		(start 276.80158 -311.07634)
		(end 273.92757 -311.07634)
		(width 0.18288)
		(layer "In11.Cu")
		(net "M_D_CPU0_SA_DQ<11>")
	)
	(segment
		(start 288.868358 -310.900826)
		(end 288.026856 -310.059324)
		(width 0.18288)
		(layer "In11.Cu")
		(net "M_D_CPU0_SA_DQ<11>")
	)
	(segment
		(start 279.077166 -310.792114)
		(end 278.193754 -311.675526)
		(width 0.18288)
		(layer "In11.Cu")
		(net "M_D_CPU0_SA_DQ<11>")
	)
	(segment
		(start 291.912294 -310.900826)
		(end 288.868358 -310.900826)
		(width 0.18288)
		(layer "In11.Cu")
		(net "M_D_CPU0_SA_DQ<11>")
	)
	(arc
		(start 334.598264 -279.474676)
		(mid 334.315562 -279.3989)
		(end 334.03286 -279.474676)
		(width 0.088646)
		(layer "In11.Cu")
		(net "M_D_CPU0_SA_DQ<11>")
	)
	(arc
		(start 338.827364 -278.66086)
		(mid 338.544662 -278.585084)
		(end 338.26196 -278.66086)
		(width 0.088646)
		(layer "In11.Cu")
		(net "M_D_CPU0_SA_DQ<11>")
	)
	(arc
		(start 336.099912 -279.150318)
		(mid 336.052233 -279.333218)
		(end 335.92135 -279.469596)
		(width 0.088646)
		(layer "In11.Cu")
		(net "M_D_CPU0_SA_DQ<11>")
	)
	(arc
		(start 342.961214 -278.66086)
		(mid 342.774016 -278.711003)
		(end 342.586818 -278.66086)
		(width 0.088646)
		(layer "In11.Cu")
		(net "M_D_CPU0_SA_DQ<11>")
	)
	(arc
		(start 342.586818 -278.66086)
		(mid 342.304116 -278.585084)
		(end 342.021414 -278.66086)
		(width 0.088646)
		(layer "In11.Cu")
		(net "M_D_CPU0_SA_DQ<11>")
	)
	(arc
		(start 336.38236 -278.66086)
		(mid 336.178025 -278.863465)
		(end 336.099912 -279.140412)
		(width 0.088646)
		(layer "In11.Cu")
		(net "M_D_CPU0_SA_DQ<11>")
	)
	(arc
		(start 336.947764 -278.66086)
		(mid 336.665062 -278.585084)
		(end 336.38236 -278.66086)
		(width 0.088646)
		(layer "In11.Cu")
		(net "M_D_CPU0_SA_DQ<11>")
	)
	(arc
		(start 334.97266 -279.474676)
		(mid 334.785462 -279.524819)
		(end 334.598264 -279.474676)
		(width 0.088646)
		(layer "In11.Cu")
		(net "M_D_CPU0_SA_DQ<11>")
	)
	(arc
		(start 343.901014 -278.66086)
		(mid 343.713816 -278.711003)
		(end 343.526618 -278.66086)
		(width 0.088646)
		(layer "In11.Cu")
		(net "M_D_CPU0_SA_DQ<11>")
	)
	(arc
		(start 345.968066 -278.336502)
		(mid 345.917902 -278.52364)
		(end 345.780868 -278.660606)
		(width 0.088646)
		(layer "In11.Cu")
		(net "M_D_CPU0_SA_DQ<11>")
	)
	(arc
		(start 346.72016 -278.012144)
		(mid 346.533106 -277.962094)
		(end 346.346018 -278.012144)
		(width 0.088646)
		(layer "In11.Cu")
		(net "M_D_CPU0_SA_DQ<11>")
	)
	(arc
		(start 345.78036 -278.66086)
		(mid 345.593306 -278.710944)
		(end 345.406218 -278.66086)
		(width 0.088646)
		(layer "In11.Cu")
		(net "M_D_CPU0_SA_DQ<11>")
	)
	(arc
		(start 341.081614 -278.66086)
		(mid 340.894416 -278.711003)
		(end 340.707218 -278.66086)
		(width 0.088646)
		(layer "In11.Cu")
		(net "M_D_CPU0_SA_DQ<11>")
	)
	(arc
		(start 340.141814 -278.66086)
		(mid 339.954616 -278.711003)
		(end 339.767418 -278.66086)
		(width 0.088646)
		(layer "In11.Cu")
		(net "M_D_CPU0_SA_DQ<11>")
	)
	(arc
		(start 335.538064 -279.474676)
		(mid 335.255362 -279.3989)
		(end 334.97266 -279.474676)
		(width 0.088646)
		(layer "In11.Cu")
		(net "M_D_CPU0_SA_DQ<11>")
	)
	(arc
		(start 339.767418 -278.66086)
		(mid 339.490605 -278.58499)
		(end 339.212174 -278.654764)
		(width 0.088646)
		(layer "In11.Cu")
		(net "M_D_CPU0_SA_DQ<11>")
	)
	(arc
		(start 339.20176 -278.66086)
		(mid 339.014562 -278.711003)
		(end 338.827364 -278.66086)
		(width 0.088646)
		(layer "In11.Cu")
		(net "M_D_CPU0_SA_DQ<11>")
	)
	(arc
		(start 347.285818 -278.012144)
		(mid 347.011589 -278.088069)
		(end 346.735146 -278.02078)
		(width 0.088646)
		(layer "In11.Cu")
		(net "M_D_CPU0_SA_DQ<11>")
	)
	(arc
		(start 345.406218 -278.66086)
		(mid 345.132019 -278.585025)
		(end 344.855546 -278.652224)
		(width 0.088646)
		(layer "In11.Cu")
		(net "M_D_CPU0_SA_DQ<11>")
	)
	(arc
		(start 342.021414 -278.66086)
		(mid 341.834216 -278.711003)
		(end 341.647018 -278.66086)
		(width 0.088646)
		(layer "In11.Cu")
		(net "M_D_CPU0_SA_DQ<11>")
	)
	(arc
		(start 347.65996 -278.012144)
		(mid 347.472906 -277.962094)
		(end 347.285818 -278.012144)
		(width 0.088646)
		(layer "In11.Cu")
		(net "M_D_CPU0_SA_DQ<11>")
	)
	(arc
		(start 340.707218 -278.66086)
		(mid 340.433019 -278.585025)
		(end 340.156546 -278.652224)
		(width 0.088646)
		(layer "In11.Cu")
		(net "M_D_CPU0_SA_DQ<11>")
	)
	(arc
		(start 333.750412 -279.964134)
		(mid 333.702733 -280.147034)
		(end 333.57185 -280.283412)
		(width 0.088646)
		(layer "In11.Cu")
		(net "M_D_CPU0_SA_DQ<11>")
	)
	(arc
		(start 333.56296 -280.288492)
		(mid 333.360674 -280.487473)
		(end 333.280512 -280.759662)
		(width 0.088646)
		(layer "In11.Cu")
		(net "M_D_CPU0_SA_DQ<11>")
	)
	(arc
		(start 346.060014 -278.177498)
		(mid 345.992684 -278.244656)
		(end 345.968066 -278.336502)
		(width 0.088646)
		(layer "In11.Cu")
		(net "M_D_CPU0_SA_DQ<11>")
	)
	(arc
		(start 334.03286 -279.474676)
		(mid 333.828525 -279.677281)
		(end 333.750412 -279.954228)
		(width 0.088646)
		(layer "In11.Cu")
		(net "M_D_CPU0_SA_DQ<11>")
	)
	(arc
		(start 344.840814 -278.66086)
		(mid 344.653616 -278.711003)
		(end 344.466418 -278.66086)
		(width 0.088646)
		(layer "In11.Cu")
		(net "M_D_CPU0_SA_DQ<11>")
	)
	(arc
		(start 338.26196 -278.66086)
		(mid 338.074762 -278.711003)
		(end 337.887564 -278.66086)
		(width 0.088646)
		(layer "In11.Cu")
		(net "M_D_CPU0_SA_DQ<11>")
	)
	(arc
		(start 337.887564 -278.66086)
		(mid 337.604862 -278.585084)
		(end 337.32216 -278.66086)
		(width 0.088646)
		(layer "In11.Cu")
		(net "M_D_CPU0_SA_DQ<11>")
	)
	(arc
		(start 337.32216 -278.66086)
		(mid 337.134962 -278.711003)
		(end 336.947764 -278.66086)
		(width 0.088646)
		(layer "In11.Cu")
		(net "M_D_CPU0_SA_DQ<11>")
	)
	(arc
		(start 341.647018 -278.66086)
		(mid 341.372819 -278.585025)
		(end 341.096346 -278.652224)
		(width 0.088646)
		(layer "In11.Cu")
		(net "M_D_CPU0_SA_DQ<11>")
	)
	(arc
		(start 344.466418 -278.66086)
		(mid 344.192219 -278.585025)
		(end 343.915746 -278.652224)
		(width 0.088646)
		(layer "In11.Cu")
		(net "M_D_CPU0_SA_DQ<11>")
	)
	(arc
		(start 335.91246 -279.474676)
		(mid 335.725262 -279.524819)
		(end 335.538064 -279.474676)
		(width 0.088646)
		(layer "In11.Cu")
		(net "M_D_CPU0_SA_DQ<11>")
	)
	(arc
		(start 343.526618 -278.66086)
		(mid 343.252419 -278.585025)
		(end 342.975946 -278.652224)
		(width 0.088646)
		(layer "In11.Cu")
		(net "M_D_CPU0_SA_DQ<11>")
	)
	(segment
		(start 266.197842 -306.328572)
		(end 265.769344 -306.328572)
		(width 0.20066)
		(layer "F.Cu")
		(net "M_D_CPU0_SA_DQ<10>")
	)
	(segment
		(start 265.769344 -306.328572)
		(end 265.601958 -306.161186)
		(width 0.20066)
		(layer "F.Cu")
		(net "M_D_CPU0_SA_DQ<10>")
	)
	(segment
		(start 262.50011 -305.681634)
		(end 261.762748 -305.681634)
		(width 0.20066)
		(layer "F.Cu")
		(net "M_D_CPU0_SA_DQ<10>")
	)
	(segment
		(start 262.765286 -305.691794)
		(end 262.51027 -305.691794)
		(width 0.101854)
		(layer "F.Cu")
		(net "M_D_CPU0_SA_DQ<10>")
	)
	(segment
		(start 347.942916 -278.614378)
		(end 347.942916 -279.150064)
		(width 0.20066)
		(layer "F.Cu")
		(net "M_D_CPU0_SA_DQ<10>")
	)
	(segment
		(start 265.601958 -305.835558)
		(end 265.458194 -305.691794)
		(width 0.20066)
		(layer "F.Cu")
		(net "M_D_CPU0_SA_DQ<10>")
	)
	(segment
		(start 268.829282 -306.116736)
		(end 267.724382 -306.116736)
		(width 0.20066)
		(layer "F.Cu")
		(net "M_D_CPU0_SA_DQ<10>")
	)
	(segment
		(start 262.51027 -305.691794)
		(end 262.50011 -305.681634)
		(width 0.101854)
		(layer "F.Cu")
		(net "M_D_CPU0_SA_DQ<10>")
	)
	(segment
		(start 267.724382 -306.116736)
		(end 266.409678 -306.116736)
		(width 0.20066)
		(layer "F.Cu")
		(net "M_D_CPU0_SA_DQ<10>")
	)
	(segment
		(start 265.458194 -305.691794)
		(end 264.825226 -305.691794)
		(width 0.20066)
		(layer "F.Cu")
		(net "M_D_CPU0_SA_DQ<10>")
	)
	(segment
		(start 261.327646 -306.116736)
		(end 260.180582 -306.116736)
		(width 0.20066)
		(layer "F.Cu")
		(net "M_D_CPU0_SA_DQ<10>")
	)
	(segment
		(start 266.409678 -306.116736)
		(end 266.197842 -306.328572)
		(width 0.20066)
		(layer "F.Cu")
		(net "M_D_CPU0_SA_DQ<10>")
	)
	(segment
		(start 265.601958 -306.161186)
		(end 265.601958 -305.835558)
		(width 0.20066)
		(layer "F.Cu")
		(net "M_D_CPU0_SA_DQ<10>")
	)
	(segment
		(start 261.762748 -305.681634)
		(end 261.327646 -306.116736)
		(width 0.20066)
		(layer "F.Cu")
		(net "M_D_CPU0_SA_DQ<10>")
	)
	(segment
		(start 264.825226 -305.691794)
		(end 262.765286 -305.691794)
		(width 0.1016)
		(layer "F.Cu")
		(net "M_D_CPU0_SA_DQ<10>")
	)
	(segment
		(start 347.942916 -279.150064)
		(end 347.942662 -279.150318)
		(width 0.20066)
		(layer "F.Cu")
		(net "M_D_CPU0_SA_DQ<10>")
	)
	(segment
		(start 308.853332 -305.69408)
		(end 307.987446 -306.559966)
		(width 0.18288)
		(layer "In11.Cu")
		(net "M_D_CPU0_SA_DQ<10>")
	)
	(segment
		(start 275.309584 -313.076844)
		(end 274.994624 -313.076844)
		(width 0.18288)
		(layer "In11.Cu")
		(net "M_D_CPU0_SA_DQ<10>")
	)
	(segment
		(start 314.33516 -304.842926)
		(end 313.711336 -304.842926)
		(width 0.18288)
		(layer "In11.Cu")
		(net "M_D_CPU0_SA_DQ<10>")
	)
	(segment
		(start 342.501728 -279.46858)
		(end 342.491314 -279.474676)
		(width 0.088646)
		(layer "In11.Cu")
		(net "M_D_CPU0_SA_DQ<10>")
	)
	(segment
		(start 331.409802 -284.024324)
		(end 322.731384 -292.702742)
		(width 0.18288)
		(layer "In11.Cu")
		(net "M_D_CPU0_SA_DQ<10>")
	)
	(segment
		(start 345.876118 -279.474676)
		(end 345.865704 -279.46858)
		(width 0.088646)
		(layer "In11.Cu")
		(net "M_D_CPU0_SA_DQ<10>")
	)
	(segment
		(start 269.980156 -306.710588)
		(end 269.423134 -306.710588)
		(width 0.18288)
		(layer "In11.Cu")
		(net "M_D_CPU0_SA_DQ<10>")
	)
	(segment
		(start 269.423134 -306.710588)
		(end 268.829282 -306.116736)
		(width 0.18288)
		(layer "In11.Cu")
		(net "M_D_CPU0_SA_DQ<10>")
	)
	(segment
		(start 274.801584 -312.883804)
		(end 274.801584 -312.532268)
		(width 0.18288)
		(layer "In11.Cu")
		(net "M_D_CPU0_SA_DQ<10>")
	)
	(segment
		(start 270.690594 -310.293258)
		(end 270.690594 -307.421026)
		(width 0.18288)
		(layer "In11.Cu")
		(net "M_D_CPU0_SA_DQ<10>")
	)
	(segment
		(start 341.561674 -279.46858)
		(end 341.55126 -279.474676)
		(width 0.088646)
		(layer "In11.Cu")
		(net "M_D_CPU0_SA_DQ<10>")
	)
	(segment
		(start 275.695664 -312.339228)
		(end 275.502624 -312.532268)
		(width 0.18288)
		(layer "In11.Cu")
		(net "M_D_CPU0_SA_DQ<10>")
	)
	(segment
		(start 299.743622 -312.492898)
		(end 298.260262 -312.492898)
		(width 0.18288)
		(layer "In11.Cu")
		(net "M_D_CPU0_SA_DQ<10>")
	)
	(segment
		(start 274.994624 -313.076844)
		(end 274.801584 -312.883804)
		(width 0.18288)
		(layer "In11.Cu")
		(net "M_D_CPU0_SA_DQ<10>")
	)
	(segment
		(start 270.762984 -310.384444)
		(end 270.690594 -310.293258)
		(width 0.18288)
		(layer "In11.Cu")
		(net "M_D_CPU0_SA_DQ<10>")
	)
	(segment
		(start 295.262808 -313.341512)
		(end 294.145462 -313.341512)
		(width 0.18288)
		(layer "In11.Cu")
		(net "M_D_CPU0_SA_DQ<10>")
	)
	(segment
		(start 334.04175 -281.097482)
		(end 334.03286 -281.102562)
		(width 0.088646)
		(layer "In11.Cu")
		(net "M_D_CPU0_SA_DQ<10>")
	)
	(segment
		(start 333.182976 -282.23464)
		(end 333.182976 -282.443428)
		(width 0.088646)
		(layer "In11.Cu")
		(net "M_D_CPU0_SA_DQ<10>")
	)
	(segment
		(start 274.608544 -312.339228)
		(end 272.717768 -312.339228)
		(width 0.18288)
		(layer "In11.Cu")
		(net "M_D_CPU0_SA_DQ<10>")
	)
	(segment
		(start 333.182976 -282.443428)
		(end 331.780134 -283.84627)
		(width 0.088646)
		(layer "In11.Cu")
		(net "M_D_CPU0_SA_DQ<10>")
	)
	(segment
		(start 334.220312 -280.759662)
		(end 334.220312 -280.778204)
		(width 0.088646)
		(layer "In11.Cu")
		(net "M_D_CPU0_SA_DQ<10>")
	)
	(segment
		(start 298.260262 -312.492898)
		(end 298.067222 -312.685938)
		(width 0.18288)
		(layer "In11.Cu")
		(net "M_D_CPU0_SA_DQ<10>")
	)
	(segment
		(start 285.006796 -311.810908)
		(end 284.328108 -312.489596)
		(width 0.18288)
		(layer "In11.Cu")
		(net "M_D_CPU0_SA_DQ<10>")
	)
	(segment
		(start 313.711336 -304.842926)
		(end 312.860182 -305.69408)
		(width 0.18288)
		(layer "In11.Cu")
		(net "M_D_CPU0_SA_DQ<10>")
	)
	(segment
		(start 301.762922 -310.473598)
		(end 299.743622 -312.492898)
		(width 0.18288)
		(layer "In11.Cu")
		(net "M_D_CPU0_SA_DQ<10>")
	)
	(segment
		(start 284.328108 -312.489596)
		(end 281.077924 -312.489596)
		(width 0.18288)
		(layer "In11.Cu")
		(net "M_D_CPU0_SA_DQ<10>")
	)
	(segment
		(start 333.750412 -281.582114)
		(end 333.750412 -281.667204)
		(width 0.088646)
		(layer "In11.Cu")
		(net "M_D_CPU0_SA_DQ<10>")
	)
	(segment
		(start 288.886392 -312.463688)
		(end 288.233612 -311.810908)
		(width 0.18288)
		(layer "In11.Cu")
		(net "M_D_CPU0_SA_DQ<10>")
	)
	(segment
		(start 276.505416 -312.339228)
		(end 275.695664 -312.339228)
		(width 0.18288)
		(layer "In11.Cu")
		(net "M_D_CPU0_SA_DQ<10>")
	)
	(segment
		(start 347.36405 -278.706072)
		(end 347.285818 -278.66086)
		(width 0.088646)
		(layer "In11.Cu")
		(net "M_D_CPU0_SA_DQ<10>")
	)
	(segment
		(start 297.559222 -313.437524)
		(end 297.366182 -313.244484)
		(width 0.18288)
		(layer "In11.Cu")
		(net "M_D_CPU0_SA_DQ<10>")
	)
	(segment
		(start 302.465486 -310.182514)
		(end 301.762922 -310.473598)
		(width 0.18288)
		(layer "In11.Cu")
		(net "M_D_CPU0_SA_DQ<10>")
	)
	(segment
		(start 341.176864 -279.474676)
		(end 341.162132 -279.46604)
		(width 0.088646)
		(layer "In11.Cu")
		(net "M_D_CPU0_SA_DQ<10>")
	)
	(segment
		(start 279.057862 -313.341512)
		(end 278.776176 -313.059826)
		(width 0.18288)
		(layer "In11.Cu")
		(net "M_D_CPU0_SA_DQ<10>")
	)
	(segment
		(start 297.173142 -312.477658)
		(end 296.126662 -312.477658)
		(width 0.18288)
		(layer "In11.Cu")
		(net "M_D_CPU0_SA_DQ<10>")
	)
	(segment
		(start 281.077924 -312.489596)
		(end 280.226008 -313.341512)
		(width 0.18288)
		(layer "In11.Cu")
		(net "M_D_CPU0_SA_DQ<10>")
	)
	(segment
		(start 288.233612 -311.810908)
		(end 285.006796 -311.810908)
		(width 0.18288)
		(layer "In11.Cu")
		(net "M_D_CPU0_SA_DQ<10>")
	)
	(segment
		(start 298.067222 -313.244484)
		(end 297.874182 -313.437524)
		(width 0.18288)
		(layer "In11.Cu")
		(net "M_D_CPU0_SA_DQ<10>")
	)
	(segment
		(start 302.744378 -309.903622)
		(end 302.465486 -310.182514)
		(width 0.18288)
		(layer "In11.Cu")
		(net "M_D_CPU0_SA_DQ<10>")
	)
	(segment
		(start 339.297264 -279.474676)
		(end 339.282532 -279.46604)
		(width 0.088646)
		(layer "In11.Cu")
		(net "M_D_CPU0_SA_DQ<10>")
	)
	(segment
		(start 293.267638 -312.463688)
		(end 288.886392 -312.463688)
		(width 0.18288)
		(layer "In11.Cu")
		(net "M_D_CPU0_SA_DQ<10>")
	)
	(segment
		(start 312.860182 -305.69408)
		(end 308.853332 -305.69408)
		(width 0.18288)
		(layer "In11.Cu")
		(net "M_D_CPU0_SA_DQ<10>")
	)
	(segment
		(start 270.690594 -307.421026)
		(end 269.980156 -306.710588)
		(width 0.18288)
		(layer "In11.Cu")
		(net "M_D_CPU0_SA_DQ<10>")
	)
	(segment
		(start 297.366182 -312.670698)
		(end 297.173142 -312.477658)
		(width 0.18288)
		(layer "In11.Cu")
		(net "M_D_CPU0_SA_DQ<10>")
	)
	(segment
		(start 318.921384 -297.47718)
		(end 318.921384 -300.256702)
		(width 0.18288)
		(layer "In11.Cu")
		(net "M_D_CPU0_SA_DQ<10>")
	)
	(segment
		(start 344.936064 -279.474676)
		(end 344.921332 -279.46604)
		(width 0.088646)
		(layer "In11.Cu")
		(net "M_D_CPU0_SA_DQ<10>")
	)
	(segment
		(start 331.587856 -283.84627)
		(end 331.409802 -284.024324)
		(width 0.088646)
		(layer "In11.Cu")
		(net "M_D_CPU0_SA_DQ<10>")
	)
	(segment
		(start 275.502624 -312.883804)
		(end 275.309584 -313.076844)
		(width 0.18288)
		(layer "In11.Cu")
		(net "M_D_CPU0_SA_DQ<10>")
	)
	(segment
		(start 298.067222 -312.685938)
		(end 298.067222 -313.244484)
		(width 0.18288)
		(layer "In11.Cu")
		(net "M_D_CPU0_SA_DQ<10>")
	)
	(segment
		(start 322.731384 -292.702742)
		(end 322.731384 -293.66718)
		(width 0.18288)
		(layer "In11.Cu")
		(net "M_D_CPU0_SA_DQ<10>")
	)
	(segment
		(start 278.776176 -313.059826)
		(end 277.226014 -313.059826)
		(width 0.18288)
		(layer "In11.Cu")
		(net "M_D_CPU0_SA_DQ<10>")
	)
	(segment
		(start 307.987446 -306.559966)
		(end 307.658262 -306.559966)
		(width 0.18288)
		(layer "In11.Cu")
		(net "M_D_CPU0_SA_DQ<10>")
	)
	(segment
		(start 322.731384 -293.66718)
		(end 318.921384 -297.47718)
		(width 0.18288)
		(layer "In11.Cu")
		(net "M_D_CPU0_SA_DQ<10>")
	)
	(segment
		(start 280.226008 -313.341512)
		(end 279.057862 -313.341512)
		(width 0.18288)
		(layer "In11.Cu")
		(net "M_D_CPU0_SA_DQ<10>")
	)
	(segment
		(start 274.801584 -312.532268)
		(end 274.608544 -312.339228)
		(width 0.18288)
		(layer "In11.Cu")
		(net "M_D_CPU0_SA_DQ<10>")
	)
	(segment
		(start 272.717768 -312.339228)
		(end 270.762984 -310.384444)
		(width 0.18288)
		(layer "In11.Cu")
		(net "M_D_CPU0_SA_DQ<10>")
	)
	(segment
		(start 346.735146 -278.652224)
		(end 346.720414 -278.66086)
		(width 0.088646)
		(layer "In11.Cu")
		(net "M_D_CPU0_SA_DQ<10>")
	)
	(segment
		(start 307.658262 -306.559966)
		(end 306.730146 -307.488082)
		(width 0.18288)
		(layer "In11.Cu")
		(net "M_D_CPU0_SA_DQ<10>")
	)
	(segment
		(start 331.780134 -283.84627)
		(end 331.587856 -283.84627)
		(width 0.088646)
		(layer "In11.Cu")
		(net "M_D_CPU0_SA_DQ<10>")
	)
	(segment
		(start 336.39125 -280.283412)
		(end 336.38236 -280.288492)
		(width 0.088646)
		(layer "In11.Cu")
		(net "M_D_CPU0_SA_DQ<10>")
	)
	(segment
		(start 336.569812 -279.954228)
		(end 336.569812 -279.964134)
		(width 0.088646)
		(layer "In11.Cu")
		(net "M_D_CPU0_SA_DQ<10>")
	)
	(segment
		(start 333.750412 -281.667204)
		(end 333.182976 -282.23464)
		(width 0.088646)
		(layer "In11.Cu")
		(net "M_D_CPU0_SA_DQ<10>")
	)
	(segment
		(start 340.237064 -279.474676)
		(end 340.222332 -279.46604)
		(width 0.088646)
		(layer "In11.Cu")
		(net "M_D_CPU0_SA_DQ<10>")
	)
	(segment
		(start 294.145462 -313.341512)
		(end 293.267638 -312.463688)
		(width 0.18288)
		(layer "In11.Cu")
		(net "M_D_CPU0_SA_DQ<10>")
	)
	(segment
		(start 346.437712 -279.150318)
		(end 346.437712 -279.158954)
		(width 0.088646)
		(layer "In11.Cu")
		(net "M_D_CPU0_SA_DQ<10>")
	)
	(segment
		(start 304.556922 -309.152798)
		(end 302.744378 -309.903622)
		(width 0.18288)
		(layer "In11.Cu")
		(net "M_D_CPU0_SA_DQ<10>")
	)
	(segment
		(start 297.874182 -313.437524)
		(end 297.559222 -313.437524)
		(width 0.18288)
		(layer "In11.Cu")
		(net "M_D_CPU0_SA_DQ<10>")
	)
	(segment
		(start 296.126662 -312.477658)
		(end 295.262808 -313.341512)
		(width 0.18288)
		(layer "In11.Cu")
		(net "M_D_CPU0_SA_DQ<10>")
	)
	(segment
		(start 277.226014 -313.059826)
		(end 276.505416 -312.339228)
		(width 0.18288)
		(layer "In11.Cu")
		(net "M_D_CPU0_SA_DQ<10>")
	)
	(segment
		(start 297.366182 -313.244484)
		(end 297.366182 -312.670698)
		(width 0.18288)
		(layer "In11.Cu")
		(net "M_D_CPU0_SA_DQ<10>")
	)
	(segment
		(start 275.502624 -312.532268)
		(end 275.502624 -312.883804)
		(width 0.18288)
		(layer "In11.Cu")
		(net "M_D_CPU0_SA_DQ<10>")
	)
	(segment
		(start 306.730146 -307.488082)
		(end 305.861974 -307.847746)
		(width 0.18288)
		(layer "In11.Cu")
		(net "M_D_CPU0_SA_DQ<10>")
	)
	(segment
		(start 346.720414 -278.66086)
		(end 346.714318 -278.664416)
		(width 0.088646)
		(layer "In11.Cu")
		(net "M_D_CPU0_SA_DQ<10>")
	)
	(segment
		(start 305.861974 -307.847746)
		(end 304.556922 -309.152798)
		(width 0.18288)
		(layer "In11.Cu")
		(net "M_D_CPU0_SA_DQ<10>")
	)
	(segment
		(start 318.921384 -300.256702)
		(end 314.33516 -304.842926)
		(width 0.18288)
		(layer "In11.Cu")
		(net "M_D_CPU0_SA_DQ<10>")
	)
	(segment
		(start 343.996264 -279.474676)
		(end 343.981532 -279.46604)
		(width 0.088646)
		(layer "In11.Cu")
		(net "M_D_CPU0_SA_DQ<10>")
	)
	(arc
		(start 342.491314 -279.474676)
		(mid 342.304116 -279.524819)
		(end 342.116918 -279.474676)
		(width 0.088646)
		(layer "In11.Cu")
		(net "M_D_CPU0_SA_DQ<10>")
	)
	(arc
		(start 335.44256 -280.288492)
		(mid 335.255362 -280.338635)
		(end 335.068164 -280.288492)
		(width 0.088646)
		(layer "In11.Cu")
		(net "M_D_CPU0_SA_DQ<10>")
	)
	(arc
		(start 347.942662 -279.150318)
		(mid 347.667881 -278.909277)
		(end 347.36405 -278.706072)
		(width 0.088646)
		(layer "In11.Cu")
		(net "M_D_CPU0_SA_DQ<10>")
	)
	(arc
		(start 344.921332 -279.46604)
		(mid 344.644857 -279.39872)
		(end 344.37066 -279.474676)
		(width 0.088646)
		(layer "In11.Cu")
		(net "M_D_CPU0_SA_DQ<10>")
	)
	(arc
		(start 336.569812 -279.964134)
		(mid 336.522133 -280.147034)
		(end 336.39125 -280.283412)
		(width 0.088646)
		(layer "In11.Cu")
		(net "M_D_CPU0_SA_DQ<10>")
	)
	(arc
		(start 335.068164 -280.288492)
		(mid 334.785462 -280.21275)
		(end 334.50276 -280.288492)
		(width 0.088646)
		(layer "In11.Cu")
		(net "M_D_CPU0_SA_DQ<10>")
	)
	(arc
		(start 337.79206 -279.474676)
		(mid 337.604862 -279.524819)
		(end 337.417664 -279.474676)
		(width 0.088646)
		(layer "In11.Cu")
		(net "M_D_CPU0_SA_DQ<10>")
	)
	(arc
		(start 339.282532 -279.46604)
		(mid 339.006057 -279.39872)
		(end 338.73186 -279.474676)
		(width 0.088646)
		(layer "In11.Cu")
		(net "M_D_CPU0_SA_DQ<10>")
	)
	(arc
		(start 339.67166 -279.474676)
		(mid 339.484462 -279.524819)
		(end 339.297264 -279.474676)
		(width 0.088646)
		(layer "In11.Cu")
		(net "M_D_CPU0_SA_DQ<10>")
	)
	(arc
		(start 338.73186 -279.474676)
		(mid 338.544662 -279.524819)
		(end 338.357464 -279.474676)
		(width 0.088646)
		(layer "In11.Cu")
		(net "M_D_CPU0_SA_DQ<10>")
	)
	(arc
		(start 345.31046 -279.474676)
		(mid 345.123262 -279.524819)
		(end 344.936064 -279.474676)
		(width 0.088646)
		(layer "In11.Cu")
		(net "M_D_CPU0_SA_DQ<10>")
	)
	(arc
		(start 346.437712 -279.158954)
		(mid 346.385442 -279.341319)
		(end 346.250514 -279.474676)
		(width 0.088646)
		(layer "In11.Cu")
		(net "M_D_CPU0_SA_DQ<10>")
	)
	(arc
		(start 334.50276 -280.288492)
		(mid 334.300474 -280.487473)
		(end 334.220312 -280.759662)
		(width 0.088646)
		(layer "In11.Cu")
		(net "M_D_CPU0_SA_DQ<10>")
	)
	(arc
		(start 336.85226 -279.474676)
		(mid 336.647925 -279.677281)
		(end 336.569812 -279.954228)
		(width 0.088646)
		(layer "In11.Cu")
		(net "M_D_CPU0_SA_DQ<10>")
	)
	(arc
		(start 346.250514 -279.474676)
		(mid 346.063316 -279.524819)
		(end 345.876118 -279.474676)
		(width 0.088646)
		(layer "In11.Cu")
		(net "M_D_CPU0_SA_DQ<10>")
	)
	(arc
		(start 342.116918 -279.474676)
		(mid 341.840105 -279.398806)
		(end 341.561674 -279.46858)
		(width 0.088646)
		(layer "In11.Cu")
		(net "M_D_CPU0_SA_DQ<10>")
	)
	(arc
		(start 341.162132 -279.46604)
		(mid 340.885657 -279.39872)
		(end 340.61146 -279.474676)
		(width 0.088646)
		(layer "In11.Cu")
		(net "M_D_CPU0_SA_DQ<10>")
	)
	(arc
		(start 347.285818 -278.66086)
		(mid 347.011619 -278.585025)
		(end 346.735146 -278.652224)
		(width 0.088646)
		(layer "In11.Cu")
		(net "M_D_CPU0_SA_DQ<10>")
	)
	(arc
		(start 340.61146 -279.474676)
		(mid 340.424262 -279.524819)
		(end 340.237064 -279.474676)
		(width 0.088646)
		(layer "In11.Cu")
		(net "M_D_CPU0_SA_DQ<10>")
	)
	(arc
		(start 334.220312 -280.778204)
		(mid 334.172633 -280.961104)
		(end 334.04175 -281.097482)
		(width 0.088646)
		(layer "In11.Cu")
		(net "M_D_CPU0_SA_DQ<10>")
	)
	(arc
		(start 344.37066 -279.474676)
		(mid 344.183462 -279.524819)
		(end 343.996264 -279.474676)
		(width 0.088646)
		(layer "In11.Cu")
		(net "M_D_CPU0_SA_DQ<10>")
	)
	(arc
		(start 336.007964 -280.288492)
		(mid 335.725262 -280.21275)
		(end 335.44256 -280.288492)
		(width 0.088646)
		(layer "In11.Cu")
		(net "M_D_CPU0_SA_DQ<10>")
	)
	(arc
		(start 343.981532 -279.46604)
		(mid 343.705057 -279.39872)
		(end 343.43086 -279.474676)
		(width 0.088646)
		(layer "In11.Cu")
		(net "M_D_CPU0_SA_DQ<10>")
	)
	(arc
		(start 346.714318 -278.664416)
		(mid 346.511731 -278.870767)
		(end 346.437712 -279.150318)
		(width 0.088646)
		(layer "In11.Cu")
		(net "M_D_CPU0_SA_DQ<10>")
	)
	(arc
		(start 338.357464 -279.474676)
		(mid 338.074762 -279.3989)
		(end 337.79206 -279.474676)
		(width 0.088646)
		(layer "In11.Cu")
		(net "M_D_CPU0_SA_DQ<10>")
	)
	(arc
		(start 337.417664 -279.474676)
		(mid 337.134962 -279.3989)
		(end 336.85226 -279.474676)
		(width 0.088646)
		(layer "In11.Cu")
		(net "M_D_CPU0_SA_DQ<10>")
	)
	(arc
		(start 343.056464 -279.474676)
		(mid 342.779905 -279.398933)
		(end 342.501728 -279.46858)
		(width 0.088646)
		(layer "In11.Cu")
		(net "M_D_CPU0_SA_DQ<10>")
	)
	(arc
		(start 345.865704 -279.46858)
		(mid 345.587272 -279.398734)
		(end 345.31046 -279.474676)
		(width 0.088646)
		(layer "In11.Cu")
		(net "M_D_CPU0_SA_DQ<10>")
	)
	(arc
		(start 340.222332 -279.46604)
		(mid 339.945857 -279.39872)
		(end 339.67166 -279.474676)
		(width 0.088646)
		(layer "In11.Cu")
		(net "M_D_CPU0_SA_DQ<10>")
	)
	(arc
		(start 336.38236 -280.288492)
		(mid 336.195162 -280.338635)
		(end 336.007964 -280.288492)
		(width 0.088646)
		(layer "In11.Cu")
		(net "M_D_CPU0_SA_DQ<10>")
	)
	(arc
		(start 334.03286 -281.102562)
		(mid 333.828525 -281.305167)
		(end 333.750412 -281.582114)
		(width 0.088646)
		(layer "In11.Cu")
		(net "M_D_CPU0_SA_DQ<10>")
	)
	(arc
		(start 341.55126 -279.474676)
		(mid 341.364062 -279.524819)
		(end 341.176864 -279.474676)
		(width 0.088646)
		(layer "In11.Cu")
		(net "M_D_CPU0_SA_DQ<10>")
	)
	(arc
		(start 343.43086 -279.474676)
		(mid 343.243662 -279.524819)
		(end 343.056464 -279.474676)
		(width 0.088646)
		(layer "In11.Cu")
		(net "M_D_CPU0_SA_DQ<10>")
	)
	(segment
		(start 261.830312 -315.891672)
		(end 261.381494 -315.891672)
		(width 0.20066)
		(layer "F.Cu")
		(net "M_D_CPU0_SA_DQ<0>")
	)
	(segment
		(start 257.414776 -316.316614)
		(end 256.080514 -316.316614)
		(width 0.20066)
		(layer "F.Cu")
		(net "M_D_CPU0_SA_DQ<0>")
	)
	(segment
		(start 264.729214 -316.316614)
		(end 263.624314 -316.316614)
		(width 0.20066)
		(layer "F.Cu")
		(net "M_D_CPU0_SA_DQ<0>")
	)
	(segment
		(start 263.624314 -316.316614)
		(end 262.255254 -316.316614)
		(width 0.20066)
		(layer "F.Cu")
		(net "M_D_CPU0_SA_DQ<0>")
	)
	(segment
		(start 258.49453 -315.883544)
		(end 258.28498 -316.093094)
		(width 0.20066)
		(layer "F.Cu")
		(net "M_D_CPU0_SA_DQ<0>")
	)
	(segment
		(start 257.66903 -316.570868)
		(end 257.414776 -316.316614)
		(width 0.20066)
		(layer "F.Cu")
		(net "M_D_CPU0_SA_DQ<0>")
	)
	(segment
		(start 343.713562 -276.172676)
		(end 343.713562 -276.708362)
		(width 0.20066)
		(layer "F.Cu")
		(net "M_D_CPU0_SA_DQ<0>")
	)
	(segment
		(start 259.064506 -315.891672)
		(end 259.056378 -315.883544)
		(width 0.101854)
		(layer "F.Cu")
		(net "M_D_CPU0_SA_DQ<0>")
	)
	(segment
		(start 261.381494 -315.891672)
		(end 259.31241 -315.891672)
		(width 0.1016)
		(layer "F.Cu")
		(net "M_D_CPU0_SA_DQ<0>")
	)
	(segment
		(start 259.31241 -315.891672)
		(end 259.064506 -315.891672)
		(width 0.101854)
		(layer "F.Cu")
		(net "M_D_CPU0_SA_DQ<0>")
	)
	(segment
		(start 258.28498 -316.093094)
		(end 258.28498 -316.382654)
		(width 0.20066)
		(layer "F.Cu")
		(net "M_D_CPU0_SA_DQ<0>")
	)
	(segment
		(start 262.255254 -316.316614)
		(end 261.830312 -315.891672)
		(width 0.20066)
		(layer "F.Cu")
		(net "M_D_CPU0_SA_DQ<0>")
	)
	(segment
		(start 259.056378 -315.883544)
		(end 258.49453 -315.883544)
		(width 0.20066)
		(layer "F.Cu")
		(net "M_D_CPU0_SA_DQ<0>")
	)
	(segment
		(start 258.096766 -316.570868)
		(end 257.66903 -316.570868)
		(width 0.20066)
		(layer "F.Cu")
		(net "M_D_CPU0_SA_DQ<0>")
	)
	(segment
		(start 258.28498 -316.382654)
		(end 258.096766 -316.570868)
		(width 0.20066)
		(layer "F.Cu")
		(net "M_D_CPU0_SA_DQ<0>")
	)
	(segment
		(start 343.713562 -276.708362)
		(end 343.713816 -276.708616)
		(width 0.20066)
		(layer "F.Cu")
		(net "M_D_CPU0_SA_DQ<0>")
	)
	(segment
		(start 313.693556 -303.991772)
		(end 312.843418 -304.84191)
		(width 0.18288)
		(layer "In6.Cu")
		(net "M_D_CPU0_SA_DQ<0>")
	)
	(segment
		(start 333.940912 -281.59202)
		(end 333.940912 -281.601926)
		(width 0.088646)
		(layer "In6.Cu")
		(net "M_D_CPU0_SA_DQ<0>")
	)
	(segment
		(start 338.357464 -278.82596)
		(end 338.348574 -278.83104)
		(width 0.088646)
		(layer "In6.Cu")
		(net "M_D_CPU0_SA_DQ<0>")
	)
	(segment
		(start 331.9526 -283.514038)
		(end 318.242188 -297.22445)
		(width 0.18288)
		(layer "In6.Cu")
		(net "M_D_CPU0_SA_DQ<0>")
	)
	(segment
		(start 334.128364 -281.267662)
		(end 334.119474 -281.272742)
		(width 0.088646)
		(layer "In6.Cu")
		(net "M_D_CPU0_SA_DQ<0>")
	)
	(segment
		(start 288.957766 -315.693044)
		(end 287.997138 -316.653672)
		(width 0.18288)
		(layer "In6.Cu")
		(net "M_D_CPU0_SA_DQ<0>")
	)
	(segment
		(start 333.471012 -282.516834)
		(end 332.692756 -283.29509)
		(width 0.088646)
		(layer "In6.Cu")
		(net "M_D_CPU0_SA_DQ<0>")
	)
	(segment
		(start 335.068164 -279.639776)
		(end 335.059274 -279.644856)
		(width 0.088646)
		(layer "In6.Cu")
		(net "M_D_CPU0_SA_DQ<0>")
	)
	(segment
		(start 333.471012 -282.39593)
		(end 333.471012 -282.516834)
		(width 0.088646)
		(layer "In6.Cu")
		(net "M_D_CPU0_SA_DQ<0>")
	)
	(segment
		(start 287.997138 -317.208154)
		(end 287.020762 -318.18453)
		(width 0.18288)
		(layer "In6.Cu")
		(net "M_D_CPU0_SA_DQ<0>")
	)
	(segment
		(start 339.110066 -277.513796)
		(end 339.110066 -277.536656)
		(width 0.088646)
		(layer "In6.Cu")
		(net "M_D_CPU0_SA_DQ<0>")
	)
	(segment
		(start 306.87264 -306.372006)
		(end 306.412392 -306.372006)
		(width 0.18288)
		(layer "In6.Cu")
		(net "M_D_CPU0_SA_DQ<0>")
	)
	(segment
		(start 332.692756 -283.29509)
		(end 332.171548 -283.29509)
		(width 0.088646)
		(layer "In6.Cu")
		(net "M_D_CPU0_SA_DQ<0>")
	)
	(segment
		(start 307.68163 -305.563016)
		(end 306.87264 -306.372006)
		(width 0.18288)
		(layer "In6.Cu")
		(net "M_D_CPU0_SA_DQ<0>")
	)
	(segment
		(start 275.59 -317.593472)
		(end 274.738338 -316.74181)
		(width 0.18288)
		(layer "In6.Cu")
		(net "M_D_CPU0_SA_DQ<0>")
	)
	(segment
		(start 334.598264 -280.453846)
		(end 334.589374 -280.458926)
		(width 0.088646)
		(layer "In6.Cu")
		(net "M_D_CPU0_SA_DQ<0>")
	)
	(segment
		(start 292.64229 -314.192158)
		(end 291.141404 -315.693044)
		(width 0.18288)
		(layer "In6.Cu")
		(net "M_D_CPU0_SA_DQ<0>")
	)
	(segment
		(start 334.880712 -279.964134)
		(end 334.880712 -279.982676)
		(width 0.088646)
		(layer "In6.Cu")
		(net "M_D_CPU0_SA_DQ<0>")
	)
	(segment
		(start 343.526618 -276.384258)
		(end 343.517728 -276.389338)
		(width 0.088646)
		(layer "In6.Cu")
		(net "M_D_CPU0_SA_DQ<0>")
	)
	(segment
		(start 338.170012 -279.150318)
		(end 338.170012 -279.160224)
		(width 0.088646)
		(layer "In6.Cu")
		(net "M_D_CPU0_SA_DQ<0>")
	)
	(segment
		(start 343.06256 -277.194518)
		(end 343.056464 -277.198074)
		(width 0.088646)
		(layer "In6.Cu")
		(net "M_D_CPU0_SA_DQ<0>")
	)
	(segment
		(start 342.116664 -277.198074)
		(end 342.101932 -277.20671)
		(width 0.088646)
		(layer "In6.Cu")
		(net "M_D_CPU0_SA_DQ<0>")
	)
	(segment
		(start 279.3111 -317.593472)
		(end 275.59 -317.593472)
		(width 0.18288)
		(layer "In6.Cu")
		(net "M_D_CPU0_SA_DQ<0>")
	)
	(segment
		(start 315.724286 -302.663352)
		(end 314.395866 -303.991772)
		(width 0.18288)
		(layer "In6.Cu")
		(net "M_D_CPU0_SA_DQ<0>")
	)
	(segment
		(start 308.307486 -305.303682)
		(end 307.68163 -305.563016)
		(width 0.18288)
		(layer "In6.Cu")
		(net "M_D_CPU0_SA_DQ<0>")
	)
	(segment
		(start 274.738338 -316.74181)
		(end 265.15441 -316.74181)
		(width 0.18288)
		(layer "In6.Cu")
		(net "M_D_CPU0_SA_DQ<0>")
	)
	(segment
		(start 344.02649 -276.708616)
		(end 344.083894 -276.651212)
		(width 0.088646)
		(layer "In6.Cu")
		(net "M_D_CPU0_SA_DQ<0>")
	)
	(segment
		(start 296.037254 -314.192158)
		(end 292.64229 -314.192158)
		(width 0.18288)
		(layer "In6.Cu")
		(net "M_D_CPU0_SA_DQ<0>")
	)
	(segment
		(start 287.997138 -316.653672)
		(end 287.997138 -317.208154)
		(width 0.18288)
		(layer "In6.Cu")
		(net "M_D_CPU0_SA_DQ<0>")
	)
	(segment
		(start 338.639912 -278.336502)
		(end 338.639912 -278.346408)
		(width 0.088646)
		(layer "In6.Cu")
		(net "M_D_CPU0_SA_DQ<0>")
	)
	(segment
		(start 302.270922 -308.925468)
		(end 302.270922 -308.93385)
		(width 0.18288)
		(layer "In6.Cu")
		(net "M_D_CPU0_SA_DQ<0>")
	)
	(segment
		(start 341.176864 -277.198074)
		(end 341.162132 -277.20671)
		(width 0.088646)
		(layer "In6.Cu")
		(net "M_D_CPU0_SA_DQ<0>")
	)
	(segment
		(start 332.171548 -283.29509)
		(end 331.9526 -283.514038)
		(width 0.088646)
		(layer "In6.Cu")
		(net "M_D_CPU0_SA_DQ<0>")
	)
	(segment
		(start 291.141404 -315.693044)
		(end 288.957766 -315.693044)
		(width 0.18288)
		(layer "In6.Cu")
		(net "M_D_CPU0_SA_DQ<0>")
	)
	(segment
		(start 318.242188 -299.334936)
		(end 315.724286 -301.852838)
		(width 0.18288)
		(layer "In6.Cu")
		(net "M_D_CPU0_SA_DQ<0>")
	)
	(segment
		(start 314.395866 -303.991772)
		(end 313.693556 -303.991772)
		(width 0.18288)
		(layer "In6.Cu")
		(net "M_D_CPU0_SA_DQ<0>")
	)
	(segment
		(start 312.843418 -304.84191)
		(end 308.769258 -304.84191)
		(width 0.18288)
		(layer "In6.Cu")
		(net "M_D_CPU0_SA_DQ<0>")
	)
	(segment
		(start 340.237064 -277.198074)
		(end 340.222332 -277.20671)
		(width 0.088646)
		(layer "In6.Cu")
		(net "M_D_CPU0_SA_DQ<0>")
	)
	(segment
		(start 334.410812 -280.778204)
		(end 334.410812 -280.78811)
		(width 0.088646)
		(layer "In6.Cu")
		(net "M_D_CPU0_SA_DQ<0>")
	)
	(segment
		(start 302.270922 -308.93385)
		(end 300.412912 -310.79186)
		(width 0.18288)
		(layer "In6.Cu")
		(net "M_D_CPU0_SA_DQ<0>")
	)
	(segment
		(start 298.806616 -310.79186)
		(end 298.06011 -311.538366)
		(width 0.18288)
		(layer "In6.Cu")
		(net "M_D_CPU0_SA_DQ<0>")
	)
	(segment
		(start 287.020762 -318.18453)
		(end 279.902158 -318.18453)
		(width 0.18288)
		(layer "In6.Cu")
		(net "M_D_CPU0_SA_DQ<0>")
	)
	(segment
		(start 338.827364 -278.012144)
		(end 338.818474 -278.017224)
		(width 0.088646)
		(layer "In6.Cu")
		(net "M_D_CPU0_SA_DQ<0>")
	)
	(segment
		(start 333.658464 -282.081732)
		(end 333.64424 -282.08986)
		(width 0.088646)
		(layer "In6.Cu")
		(net "M_D_CPU0_SA_DQ<0>")
	)
	(segment
		(start 308.769258 -304.84191)
		(end 308.307486 -305.303682)
		(width 0.18288)
		(layer "In6.Cu")
		(net "M_D_CPU0_SA_DQ<0>")
	)
	(segment
		(start 265.15441 -316.74181)
		(end 264.729214 -316.316614)
		(width 0.18288)
		(layer "In6.Cu")
		(net "M_D_CPU0_SA_DQ<0>")
	)
	(segment
		(start 343.713816 -276.708616)
		(end 344.02649 -276.708616)
		(width 0.088646)
		(layer "In6.Cu")
		(net "M_D_CPU0_SA_DQ<0>")
	)
	(segment
		(start 300.412912 -310.79186)
		(end 298.806616 -310.79186)
		(width 0.18288)
		(layer "In6.Cu")
		(net "M_D_CPU0_SA_DQ<0>")
	)
	(segment
		(start 343.909904 -276.389338)
		(end 343.901014 -276.384258)
		(width 0.088646)
		(layer "In6.Cu")
		(net "M_D_CPU0_SA_DQ<0>")
	)
	(segment
		(start 306.412392 -306.372006)
		(end 304.982118 -307.80228)
		(width 0.18288)
		(layer "In6.Cu")
		(net "M_D_CPU0_SA_DQ<0>")
	)
	(segment
		(start 333.658464 -282.081478)
		(end 333.658464 -282.081732)
		(width 0.088646)
		(layer "In6.Cu")
		(net "M_D_CPU0_SA_DQ<0>")
	)
	(segment
		(start 298.06011 -312.169302)
		(end 296.037254 -314.192158)
		(width 0.18288)
		(layer "In6.Cu")
		(net "M_D_CPU0_SA_DQ<0>")
	)
	(segment
		(start 304.982118 -307.80228)
		(end 302.270922 -308.925468)
		(width 0.18288)
		(layer "In6.Cu")
		(net "M_D_CPU0_SA_DQ<0>")
	)
	(segment
		(start 315.724286 -301.852838)
		(end 315.724286 -302.663352)
		(width 0.18288)
		(layer "In6.Cu")
		(net "M_D_CPU0_SA_DQ<0>")
	)
	(segment
		(start 279.902158 -318.18453)
		(end 279.3111 -317.593472)
		(width 0.18288)
		(layer "In6.Cu")
		(net "M_D_CPU0_SA_DQ<0>")
	)
	(segment
		(start 343.056464 -277.198074)
		(end 343.041732 -277.20671)
		(width 0.088646)
		(layer "In6.Cu")
		(net "M_D_CPU0_SA_DQ<0>")
	)
	(segment
		(start 318.242188 -297.22445)
		(end 318.242188 -299.334936)
		(width 0.18288)
		(layer "In6.Cu")
		(net "M_D_CPU0_SA_DQ<0>")
	)
	(segment
		(start 298.06011 -311.538366)
		(end 298.06011 -312.169302)
		(width 0.18288)
		(layer "In6.Cu")
		(net "M_D_CPU0_SA_DQ<0>")
	)
	(arc
		(start 337.887564 -279.639776)
		(mid 337.604862 -279.715552)
		(end 337.32216 -279.639776)
		(width 0.088646)
		(layer "In6.Cu")
		(net "M_D_CPU0_SA_DQ<0>")
	)
	(arc
		(start 333.514954 -282.230068)
		(mid 333.483362 -282.310449)
		(end 333.471012 -282.39593)
		(width 0.088646)
		(layer "In6.Cu")
		(net "M_D_CPU0_SA_DQ<0>")
	)
	(arc
		(start 339.110066 -277.536656)
		(mid 339.030847 -277.811341)
		(end 338.827364 -278.012144)
		(width 0.088646)
		(layer "In6.Cu")
		(net "M_D_CPU0_SA_DQ<0>")
	)
	(arc
		(start 338.818474 -278.017224)
		(mid 338.68756 -278.153584)
		(end 338.639912 -278.336502)
		(width 0.088646)
		(layer "In6.Cu")
		(net "M_D_CPU0_SA_DQ<0>")
	)
	(arc
		(start 338.639912 -278.346408)
		(mid 338.561801 -278.623357)
		(end 338.357464 -278.82596)
		(width 0.088646)
		(layer "In6.Cu")
		(net "M_D_CPU0_SA_DQ<0>")
	)
	(arc
		(start 337.32216 -279.639776)
		(mid 337.134962 -279.589633)
		(end 336.947764 -279.639776)
		(width 0.088646)
		(layer "In6.Cu")
		(net "M_D_CPU0_SA_DQ<0>")
	)
	(arc
		(start 339.67166 -277.198074)
		(mid 339.484462 -277.147931)
		(end 339.297264 -277.198074)
		(width 0.088646)
		(layer "In6.Cu")
		(net "M_D_CPU0_SA_DQ<0>")
	)
	(arc
		(start 340.222332 -277.20671)
		(mid 339.945857 -277.27403)
		(end 339.67166 -277.198074)
		(width 0.088646)
		(layer "In6.Cu")
		(net "M_D_CPU0_SA_DQ<0>")
	)
	(arc
		(start 334.880712 -279.982676)
		(mid 334.80055 -280.254865)
		(end 334.598264 -280.453846)
		(width 0.088646)
		(layer "In6.Cu")
		(net "M_D_CPU0_SA_DQ<0>")
	)
	(arc
		(start 341.55126 -277.198074)
		(mid 341.364062 -277.147931)
		(end 341.176864 -277.198074)
		(width 0.088646)
		(layer "In6.Cu")
		(net "M_D_CPU0_SA_DQ<0>")
	)
	(arc
		(start 336.38236 -279.639776)
		(mid 336.195162 -279.589633)
		(end 336.007964 -279.639776)
		(width 0.088646)
		(layer "In6.Cu")
		(net "M_D_CPU0_SA_DQ<0>")
	)
	(arc
		(start 341.162132 -277.20671)
		(mid 340.885657 -277.27403)
		(end 340.61146 -277.198074)
		(width 0.088646)
		(layer "In6.Cu")
		(net "M_D_CPU0_SA_DQ<0>")
	)
	(arc
		(start 338.170012 -279.160224)
		(mid 338.091901 -279.437173)
		(end 337.887564 -279.639776)
		(width 0.088646)
		(layer "In6.Cu")
		(net "M_D_CPU0_SA_DQ<0>")
	)
	(arc
		(start 343.901014 -276.384258)
		(mid 343.713816 -276.334115)
		(end 343.526618 -276.384258)
		(width 0.088646)
		(layer "In6.Cu")
		(net "M_D_CPU0_SA_DQ<0>")
	)
	(arc
		(start 344.083894 -276.651212)
		(mid 344.025738 -276.501099)
		(end 343.909904 -276.389338)
		(width 0.088646)
		(layer "In6.Cu")
		(net "M_D_CPU0_SA_DQ<0>")
	)
	(arc
		(start 333.940912 -281.601926)
		(mid 333.862801 -281.878875)
		(end 333.658464 -282.081478)
		(width 0.088646)
		(layer "In6.Cu")
		(net "M_D_CPU0_SA_DQ<0>")
	)
	(arc
		(start 342.101932 -277.20671)
		(mid 341.825457 -277.27403)
		(end 341.55126 -277.198074)
		(width 0.088646)
		(layer "In6.Cu")
		(net "M_D_CPU0_SA_DQ<0>")
	)
	(arc
		(start 334.589374 -280.458926)
		(mid 334.45846 -280.595286)
		(end 334.410812 -280.778204)
		(width 0.088646)
		(layer "In6.Cu")
		(net "M_D_CPU0_SA_DQ<0>")
	)
	(arc
		(start 343.339166 -276.708616)
		(mid 343.265175 -276.988182)
		(end 343.06256 -277.194518)
		(width 0.088646)
		(layer "In6.Cu")
		(net "M_D_CPU0_SA_DQ<0>")
	)
	(arc
		(start 336.947764 -279.639776)
		(mid 336.665062 -279.715552)
		(end 336.38236 -279.639776)
		(width 0.088646)
		(layer "In6.Cu")
		(net "M_D_CPU0_SA_DQ<0>")
	)
	(arc
		(start 343.041732 -277.20671)
		(mid 342.765257 -277.27403)
		(end 342.49106 -277.198074)
		(width 0.088646)
		(layer "In6.Cu")
		(net "M_D_CPU0_SA_DQ<0>")
	)
	(arc
		(start 342.49106 -277.198074)
		(mid 342.303862 -277.147931)
		(end 342.116664 -277.198074)
		(width 0.088646)
		(layer "In6.Cu")
		(net "M_D_CPU0_SA_DQ<0>")
	)
	(arc
		(start 340.61146 -277.198074)
		(mid 340.424262 -277.147931)
		(end 340.237064 -277.198074)
		(width 0.088646)
		(layer "In6.Cu")
		(net "M_D_CPU0_SA_DQ<0>")
	)
	(arc
		(start 334.119474 -281.272742)
		(mid 333.98856 -281.409102)
		(end 333.940912 -281.59202)
		(width 0.088646)
		(layer "In6.Cu")
		(net "M_D_CPU0_SA_DQ<0>")
	)
	(arc
		(start 333.64424 -282.08986)
		(mid 333.570519 -282.151594)
		(end 333.514954 -282.230068)
		(width 0.088646)
		(layer "In6.Cu")
		(net "M_D_CPU0_SA_DQ<0>")
	)
	(arc
		(start 338.348574 -278.83104)
		(mid 338.21766 -278.9674)
		(end 338.170012 -279.150318)
		(width 0.088646)
		(layer "In6.Cu")
		(net "M_D_CPU0_SA_DQ<0>")
	)
	(arc
		(start 343.517728 -276.389338)
		(mid 343.386814 -276.525698)
		(end 343.339166 -276.708616)
		(width 0.088646)
		(layer "In6.Cu")
		(net "M_D_CPU0_SA_DQ<0>")
	)
	(arc
		(start 339.297264 -277.198074)
		(mid 339.162331 -277.331428)
		(end 339.110066 -277.513796)
		(width 0.088646)
		(layer "In6.Cu")
		(net "M_D_CPU0_SA_DQ<0>")
	)
	(arc
		(start 334.410812 -280.78811)
		(mid 334.332701 -281.065059)
		(end 334.128364 -281.267662)
		(width 0.088646)
		(layer "In6.Cu")
		(net "M_D_CPU0_SA_DQ<0>")
	)
	(arc
		(start 336.007964 -279.639776)
		(mid 335.725262 -279.715552)
		(end 335.44256 -279.639776)
		(width 0.088646)
		(layer "In6.Cu")
		(net "M_D_CPU0_SA_DQ<0>")
	)
	(arc
		(start 335.44256 -279.639776)
		(mid 335.255362 -279.589633)
		(end 335.068164 -279.639776)
		(width 0.088646)
		(layer "In6.Cu")
		(net "M_D_CPU0_SA_DQ<0>")
	)
	(arc
		(start 335.059274 -279.644856)
		(mid 334.92836 -279.781216)
		(end 334.880712 -279.964134)
		(width 0.088646)
		(layer "In6.Cu")
		(net "M_D_CPU0_SA_DQ<0>")
	)
	(segment
		(start 348.412562 -258.2672)
		(end 348.412562 -258.802886)
		(width 0.20066)
		(layer "F.Cu")
		(net "M_D_CPU0_SA_CS_N<3>")
	)
	(segment
		(start 268.829282 -267.016738)
		(end 267.724382 -267.016738)
		(width 0.20066)
		(layer "F.Cu")
		(net "M_D_CPU0_SA_CS_N<3>")
	)
	(segment
		(start 348.412562 -258.802886)
		(end 348.412816 -258.80314)
		(width 0.20066)
		(layer "F.Cu")
		(net "M_D_CPU0_SA_CS_N<3>")
	)
	(segment
		(start 315.883544 -261.092442)
		(end 315.688218 -261.56412)
		(width 0.18288)
		(layer "In11.Cu")
		(net "M_D_CPU0_SA_CS_N<3>")
	)
	(segment
		(start 316.197996 -260.96214)
		(end 315.883544 -261.092442)
		(width 0.18288)
		(layer "In11.Cu")
		(net "M_D_CPU0_SA_CS_N<3>")
	)
	(segment
		(start 331.866494 -258.234434)
		(end 330.918566 -258.234434)
		(width 0.088646)
		(layer "In11.Cu")
		(net "M_D_CPU0_SA_CS_N<3>")
	)
	(segment
		(start 275.961094 -263.936226)
		(end 274.919694 -264.977626)
		(width 0.18288)
		(layer "In11.Cu")
		(net "M_D_CPU0_SA_CS_N<3>")
	)
	(segment
		(start 332.060042 -258.427982)
		(end 331.866494 -258.234434)
		(width 0.088646)
		(layer "In11.Cu")
		(net "M_D_CPU0_SA_CS_N<3>")
	)
	(segment
		(start 316.983618 -261.027164)
		(end 316.66942 -261.157466)
		(width 0.18288)
		(layer "In11.Cu")
		(net "M_D_CPU0_SA_CS_N<3>")
	)
	(segment
		(start 311.606184 -262.107172)
		(end 310.66613 -263.047226)
		(width 0.18288)
		(layer "In11.Cu")
		(net "M_D_CPU0_SA_CS_N<3>")
	)
	(segment
		(start 270.271494 -267.530326)
		(end 269.88897 -267.530326)
		(width 0.18288)
		(layer "In11.Cu")
		(net "M_D_CPU0_SA_CS_N<3>")
	)
	(segment
		(start 288.298382 -264.159492)
		(end 284.563058 -264.159492)
		(width 0.18288)
		(layer "In11.Cu")
		(net "M_D_CPU0_SA_CS_N<3>")
	)
	(segment
		(start 345.780614 -258.479036)
		(end 345.780614 -258.478782)
		(width 0.088646)
		(layer "In11.Cu")
		(net "M_D_CPU0_SA_CS_N<3>")
	)
	(segment
		(start 342.031828 -258.484878)
		(end 342.021414 -258.478782)
		(width 0.088646)
		(layer "In11.Cu")
		(net "M_D_CPU0_SA_CS_N<3>")
	)
	(segment
		(start 269.375382 -267.016738)
		(end 268.829282 -267.016738)
		(width 0.18288)
		(layer "In11.Cu")
		(net "M_D_CPU0_SA_CS_N<3>")
	)
	(segment
		(start 316.66942 -261.157466)
		(end 316.197996 -260.96214)
		(width 0.18288)
		(layer "In11.Cu")
		(net "M_D_CPU0_SA_CS_N<3>")
	)
	(segment
		(start 320.976244 -258.706112)
		(end 319.663826 -260.01853)
		(width 0.18288)
		(layer "In11.Cu")
		(net "M_D_CPU0_SA_CS_N<3>")
	)
	(segment
		(start 343.915746 -258.487418)
		(end 343.901014 -258.478782)
		(width 0.088646)
		(layer "In11.Cu")
		(net "M_D_CPU0_SA_CS_N<3>")
	)
	(segment
		(start 298.162726 -264.042906)
		(end 297.99153 -263.87171)
		(width 0.18288)
		(layer "In11.Cu")
		(net "M_D_CPU0_SA_CS_N<3>")
	)
	(segment
		(start 293.436294 -264.164826)
		(end 292.416992 -264.164826)
		(width 0.18288)
		(layer "In11.Cu")
		(net "M_D_CPU0_SA_CS_N<3>")
	)
	(segment
		(start 297.99153 -263.87171)
		(end 295.853866 -263.87171)
		(width 0.18288)
		(layer "In11.Cu")
		(net "M_D_CPU0_SA_CS_N<3>")
	)
	(segment
		(start 271.935194 -265.866626)
		(end 270.271494 -267.530326)
		(width 0.18288)
		(layer "In11.Cu")
		(net "M_D_CPU0_SA_CS_N<3>")
	)
	(segment
		(start 292.416992 -264.164826)
		(end 292.239192 -263.987026)
		(width 0.18288)
		(layer "In11.Cu")
		(net "M_D_CPU0_SA_CS_N<3>")
	)
	(segment
		(start 306.618894 -263.470136)
		(end 303.612804 -263.470136)
		(width 0.18288)
		(layer "In11.Cu")
		(net "M_D_CPU0_SA_CS_N<3>")
	)
	(segment
		(start 282.137866 -264.938256)
		(end 281.214322 -264.938256)
		(width 0.18288)
		(layer "In11.Cu")
		(net "M_D_CPU0_SA_CS_N<3>")
	)
	(segment
		(start 279.315672 -264.041128)
		(end 279.010618 -263.736074)
		(width 0.18288)
		(layer "In11.Cu")
		(net "M_D_CPU0_SA_CS_N<3>")
	)
	(segment
		(start 299.5295 -264.042906)
		(end 298.162726 -264.042906)
		(width 0.18288)
		(layer "In11.Cu")
		(net "M_D_CPU0_SA_CS_N<3>")
	)
	(segment
		(start 318.47663 -260.01853)
		(end 317.178944 -260.55574)
		(width 0.18288)
		(layer "In11.Cu")
		(net "M_D_CPU0_SA_CS_N<3>")
	)
	(segment
		(start 338.827618 -258.478782)
		(end 338.817204 -258.484878)
		(width 0.088646)
		(layer "In11.Cu")
		(net "M_D_CPU0_SA_CS_N<3>")
	)
	(segment
		(start 313.332114 -261.658354)
		(end 312.883296 -262.107172)
		(width 0.18288)
		(layer "In11.Cu")
		(net "M_D_CPU0_SA_CS_N<3>")
	)
	(segment
		(start 299.67428 -264.187686)
		(end 299.5295 -264.042906)
		(width 0.18288)
		(layer "In11.Cu")
		(net "M_D_CPU0_SA_CS_N<3>")
	)
	(segment
		(start 341.096346 -258.487418)
		(end 341.081614 -258.478782)
		(width 0.088646)
		(layer "In11.Cu")
		(net "M_D_CPU0_SA_CS_N<3>")
	)
	(segment
		(start 281.214322 -264.938256)
		(end 280.317194 -264.041128)
		(width 0.18288)
		(layer "In11.Cu")
		(net "M_D_CPU0_SA_CS_N<3>")
	)
	(segment
		(start 295.853866 -263.87171)
		(end 295.68521 -264.040366)
		(width 0.18288)
		(layer "In11.Cu")
		(net "M_D_CPU0_SA_CS_N<3>")
	)
	(segment
		(start 314.517786 -261.658354)
		(end 313.332114 -261.658354)
		(width 0.18288)
		(layer "In11.Cu")
		(net "M_D_CPU0_SA_CS_N<3>")
	)
	(segment
		(start 319.663826 -260.01853)
		(end 318.47663 -260.01853)
		(width 0.18288)
		(layer "In11.Cu")
		(net "M_D_CPU0_SA_CS_N<3>")
	)
	(segment
		(start 288.470848 -263.987026)
		(end 288.298382 -264.159492)
		(width 0.18288)
		(layer "In11.Cu")
		(net "M_D_CPU0_SA_CS_N<3>")
	)
	(segment
		(start 274.919694 -264.977626)
		(end 273.827494 -264.977626)
		(width 0.18288)
		(layer "In11.Cu")
		(net "M_D_CPU0_SA_CS_N<3>")
	)
	(segment
		(start 314.902342 -261.498842)
		(end 314.517786 -261.658354)
		(width 0.18288)
		(layer "In11.Cu")
		(net "M_D_CPU0_SA_CS_N<3>")
	)
	(segment
		(start 278.018494 -264.215626)
		(end 277.408894 -264.215626)
		(width 0.18288)
		(layer "In11.Cu")
		(net "M_D_CPU0_SA_CS_N<3>")
	)
	(segment
		(start 277.129494 -263.936226)
		(end 275.961094 -263.936226)
		(width 0.18288)
		(layer "In11.Cu")
		(net "M_D_CPU0_SA_CS_N<3>")
	)
	(segment
		(start 346.735146 -259.118862)
		(end 346.720414 -259.127498)
		(width 0.088646)
		(layer "In11.Cu")
		(net "M_D_CPU0_SA_CS_N<3>")
	)
	(segment
		(start 273.827494 -264.977626)
		(end 272.938494 -265.866626)
		(width 0.18288)
		(layer "In11.Cu")
		(net "M_D_CPU0_SA_CS_N<3>")
	)
	(segment
		(start 329.728576 -258.234434)
		(end 329.256898 -258.706112)
		(width 0.18288)
		(layer "In11.Cu")
		(net "M_D_CPU0_SA_CS_N<3>")
	)
	(segment
		(start 295.68521 -264.040366)
		(end 293.560754 -264.040366)
		(width 0.18288)
		(layer "In11.Cu")
		(net "M_D_CPU0_SA_CS_N<3>")
	)
	(segment
		(start 315.688218 -261.56412)
		(end 315.37402 -261.694422)
		(width 0.18288)
		(layer "In11.Cu")
		(net "M_D_CPU0_SA_CS_N<3>")
	)
	(segment
		(start 348.041468 -258.903978)
		(end 347.71838 -259.093462)
		(width 0.088646)
		(layer "In11.Cu")
		(net "M_D_CPU0_SA_CS_N<3>")
	)
	(segment
		(start 280.317194 -264.041128)
		(end 279.315672 -264.041128)
		(width 0.18288)
		(layer "In11.Cu")
		(net "M_D_CPU0_SA_CS_N<3>")
	)
	(segment
		(start 317.178944 -260.55574)
		(end 316.983618 -261.027164)
		(width 0.18288)
		(layer "In11.Cu")
		(net "M_D_CPU0_SA_CS_N<3>")
	)
	(segment
		(start 272.938494 -265.866626)
		(end 271.935194 -265.866626)
		(width 0.18288)
		(layer "In11.Cu")
		(net "M_D_CPU0_SA_CS_N<3>")
	)
	(segment
		(start 312.883296 -262.107172)
		(end 311.606184 -262.107172)
		(width 0.18288)
		(layer "In11.Cu")
		(net "M_D_CPU0_SA_CS_N<3>")
	)
	(segment
		(start 277.408894 -264.215626)
		(end 277.129494 -263.936226)
		(width 0.18288)
		(layer "In11.Cu")
		(net "M_D_CPU0_SA_CS_N<3>")
	)
	(segment
		(start 342.971374 -258.484878)
		(end 342.96096 -258.478782)
		(width 0.088646)
		(layer "In11.Cu")
		(net "M_D_CPU0_SA_CS_N<3>")
	)
	(segment
		(start 346.346018 -259.127498)
		(end 346.060014 -258.962144)
		(width 0.088646)
		(layer "In11.Cu")
		(net "M_D_CPU0_SA_CS_N<3>")
	)
	(segment
		(start 292.239192 -263.987026)
		(end 288.470848 -263.987026)
		(width 0.18288)
		(layer "In11.Cu")
		(net "M_D_CPU0_SA_CS_N<3>")
	)
	(segment
		(start 302.895254 -264.187686)
		(end 299.67428 -264.187686)
		(width 0.18288)
		(layer "In11.Cu")
		(net "M_D_CPU0_SA_CS_N<3>")
	)
	(segment
		(start 283.034994 -264.041128)
		(end 282.137866 -264.938256)
		(width 0.18288)
		(layer "In11.Cu")
		(net "M_D_CPU0_SA_CS_N<3>")
	)
	(segment
		(start 339.216746 -258.487418)
		(end 339.202014 -258.478782)
		(width 0.088646)
		(layer "In11.Cu")
		(net "M_D_CPU0_SA_CS_N<3>")
	)
	(segment
		(start 310.66613 -263.047226)
		(end 307.041804 -263.047226)
		(width 0.18288)
		(layer "In11.Cu")
		(net "M_D_CPU0_SA_CS_N<3>")
	)
	(segment
		(start 269.88897 -267.530326)
		(end 269.375382 -267.016738)
		(width 0.18288)
		(layer "In11.Cu")
		(net "M_D_CPU0_SA_CS_N<3>")
	)
	(segment
		(start 315.37402 -261.694422)
		(end 314.902342 -261.498842)
		(width 0.18288)
		(layer "In11.Cu")
		(net "M_D_CPU0_SA_CS_N<3>")
	)
	(segment
		(start 284.563058 -264.159492)
		(end 284.444694 -264.041128)
		(width 0.18288)
		(layer "In11.Cu")
		(net "M_D_CPU0_SA_CS_N<3>")
	)
	(segment
		(start 303.612804 -263.470136)
		(end 302.895254 -264.187686)
		(width 0.18288)
		(layer "In11.Cu")
		(net "M_D_CPU0_SA_CS_N<3>")
	)
	(segment
		(start 279.010618 -263.736074)
		(end 278.498046 -263.736074)
		(width 0.18288)
		(layer "In11.Cu")
		(net "M_D_CPU0_SA_CS_N<3>")
	)
	(segment
		(start 284.444694 -264.041128)
		(end 283.034994 -264.041128)
		(width 0.18288)
		(layer "In11.Cu")
		(net "M_D_CPU0_SA_CS_N<3>")
	)
	(segment
		(start 307.041804 -263.047226)
		(end 306.618894 -263.470136)
		(width 0.18288)
		(layer "In11.Cu")
		(net "M_D_CPU0_SA_CS_N<3>")
	)
	(segment
		(start 330.918566 -258.234434)
		(end 329.728576 -258.234434)
		(width 0.18288)
		(layer "In11.Cu")
		(net "M_D_CPU0_SA_CS_N<3>")
	)
	(segment
		(start 329.256898 -258.706112)
		(end 320.976244 -258.706112)
		(width 0.18288)
		(layer "In11.Cu")
		(net "M_D_CPU0_SA_CS_N<3>")
	)
	(segment
		(start 332.435962 -258.427982)
		(end 332.060042 -258.427982)
		(width 0.088646)
		(layer "In11.Cu")
		(net "M_D_CPU0_SA_CS_N<3>")
	)
	(segment
		(start 293.560754 -264.040366)
		(end 293.436294 -264.164826)
		(width 0.18288)
		(layer "In11.Cu")
		(net "M_D_CPU0_SA_CS_N<3>")
	)
	(segment
		(start 347.71838 -259.093462)
		(end 347.660214 -259.127498)
		(width 0.088646)
		(layer "In11.Cu")
		(net "M_D_CPU0_SA_CS_N<3>")
	)
	(segment
		(start 278.498046 -263.736074)
		(end 278.018494 -264.215626)
		(width 0.18288)
		(layer "In11.Cu")
		(net "M_D_CPU0_SA_CS_N<3>")
	)
	(arc
		(start 340.707218 -258.478782)
		(mid 340.424516 -258.554524)
		(end 340.141814 -258.478782)
		(width 0.088646)
		(layer "In11.Cu")
		(net "M_D_CPU0_SA_CS_N<3>")
	)
	(arc
		(start 342.021414 -258.478782)
		(mid 341.834216 -258.428639)
		(end 341.647018 -258.478782)
		(width 0.088646)
		(layer "In11.Cu")
		(net "M_D_CPU0_SA_CS_N<3>")
	)
	(arc
		(start 346.720414 -259.127498)
		(mid 346.533216 -259.177641)
		(end 346.346018 -259.127498)
		(width 0.088646)
		(layer "In11.Cu")
		(net "M_D_CPU0_SA_CS_N<3>")
	)
	(arc
		(start 345.406218 -258.478782)
		(mid 345.123516 -258.554524)
		(end 344.840814 -258.478782)
		(width 0.088646)
		(layer "In11.Cu")
		(net "M_D_CPU0_SA_CS_N<3>")
	)
	(arc
		(start 343.901014 -258.478782)
		(mid 343.713816 -258.428639)
		(end 343.526618 -258.478782)
		(width 0.088646)
		(layer "In11.Cu")
		(net "M_D_CPU0_SA_CS_N<3>")
	)
	(arc
		(start 338.817204 -258.484878)
		(mid 338.538772 -258.554692)
		(end 338.26196 -258.478782)
		(width 0.088646)
		(layer "In11.Cu")
		(net "M_D_CPU0_SA_CS_N<3>")
	)
	(arc
		(start 337.887564 -258.478782)
		(mid 337.604862 -258.554524)
		(end 337.32216 -258.478782)
		(width 0.088646)
		(layer "In11.Cu")
		(net "M_D_CPU0_SA_CS_N<3>")
	)
	(arc
		(start 345.968066 -258.80314)
		(mid 345.917773 -258.615964)
		(end 345.780614 -258.479036)
		(width 0.088646)
		(layer "In11.Cu")
		(net "M_D_CPU0_SA_CS_N<3>")
	)
	(arc
		(start 335.068164 -258.478782)
		(mid 334.785462 -258.554524)
		(end 334.50276 -258.478782)
		(width 0.088646)
		(layer "In11.Cu")
		(net "M_D_CPU0_SA_CS_N<3>")
	)
	(arc
		(start 341.081614 -258.478782)
		(mid 340.894416 -258.428639)
		(end 340.707218 -258.478782)
		(width 0.088646)
		(layer "In11.Cu")
		(net "M_D_CPU0_SA_CS_N<3>")
	)
	(arc
		(start 334.128364 -258.478782)
		(mid 333.845662 -258.554524)
		(end 333.56296 -258.478782)
		(width 0.088646)
		(layer "In11.Cu")
		(net "M_D_CPU0_SA_CS_N<3>")
	)
	(arc
		(start 333.56296 -258.478782)
		(mid 333.375762 -258.428639)
		(end 333.188564 -258.478782)
		(width 0.088646)
		(layer "In11.Cu")
		(net "M_D_CPU0_SA_CS_N<3>")
	)
	(arc
		(start 334.50276 -258.478782)
		(mid 334.315562 -258.428639)
		(end 334.128364 -258.478782)
		(width 0.088646)
		(layer "In11.Cu")
		(net "M_D_CPU0_SA_CS_N<3>")
	)
	(arc
		(start 342.586564 -258.478782)
		(mid 342.310005 -258.554491)
		(end 342.031828 -258.484878)
		(width 0.088646)
		(layer "In11.Cu")
		(net "M_D_CPU0_SA_CS_N<3>")
	)
	(arc
		(start 341.647018 -258.478782)
		(mid 341.372789 -258.554707)
		(end 341.096346 -258.487418)
		(width 0.088646)
		(layer "In11.Cu")
		(net "M_D_CPU0_SA_CS_N<3>")
	)
	(arc
		(start 337.32216 -258.478782)
		(mid 337.134962 -258.428639)
		(end 336.947764 -258.478782)
		(width 0.088646)
		(layer "In11.Cu")
		(net "M_D_CPU0_SA_CS_N<3>")
	)
	(arc
		(start 347.285818 -259.127498)
		(mid 347.011619 -259.051663)
		(end 346.735146 -259.118862)
		(width 0.088646)
		(layer "In11.Cu")
		(net "M_D_CPU0_SA_CS_N<3>")
	)
	(arc
		(start 333.188564 -258.478782)
		(mid 332.905862 -258.554524)
		(end 332.62316 -258.478782)
		(width 0.088646)
		(layer "In11.Cu")
		(net "M_D_CPU0_SA_CS_N<3>")
	)
	(arc
		(start 344.840814 -258.478782)
		(mid 344.653616 -258.428639)
		(end 344.466418 -258.478782)
		(width 0.088646)
		(layer "In11.Cu")
		(net "M_D_CPU0_SA_CS_N<3>")
	)
	(arc
		(start 336.38236 -258.478782)
		(mid 336.195162 -258.428639)
		(end 336.007964 -258.478782)
		(width 0.088646)
		(layer "In11.Cu")
		(net "M_D_CPU0_SA_CS_N<3>")
	)
	(arc
		(start 336.947764 -258.478782)
		(mid 336.665062 -258.554524)
		(end 336.38236 -258.478782)
		(width 0.088646)
		(layer "In11.Cu")
		(net "M_D_CPU0_SA_CS_N<3>")
	)
	(arc
		(start 339.202014 -258.478782)
		(mid 339.014816 -258.428639)
		(end 338.827618 -258.478782)
		(width 0.088646)
		(layer "In11.Cu")
		(net "M_D_CPU0_SA_CS_N<3>")
	)
	(arc
		(start 343.526618 -258.478782)
		(mid 343.249805 -258.554618)
		(end 342.971374 -258.484878)
		(width 0.088646)
		(layer "In11.Cu")
		(net "M_D_CPU0_SA_CS_N<3>")
	)
	(arc
		(start 342.96096 -258.478782)
		(mid 342.773762 -258.428639)
		(end 342.586564 -258.478782)
		(width 0.088646)
		(layer "In11.Cu")
		(net "M_D_CPU0_SA_CS_N<3>")
	)
	(arc
		(start 344.466418 -258.478782)
		(mid 344.192189 -258.554707)
		(end 343.915746 -258.487418)
		(width 0.088646)
		(layer "In11.Cu")
		(net "M_D_CPU0_SA_CS_N<3>")
	)
	(arc
		(start 338.26196 -258.478782)
		(mid 338.074762 -258.428639)
		(end 337.887564 -258.478782)
		(width 0.088646)
		(layer "In11.Cu")
		(net "M_D_CPU0_SA_CS_N<3>")
	)
	(arc
		(start 345.780614 -258.478782)
		(mid 345.593416 -258.428639)
		(end 345.406218 -258.478782)
		(width 0.088646)
		(layer "In11.Cu")
		(net "M_D_CPU0_SA_CS_N<3>")
	)
	(arc
		(start 346.060014 -258.962144)
		(mid 345.992684 -258.894986)
		(end 345.968066 -258.80314)
		(width 0.088646)
		(layer "In11.Cu")
		(net "M_D_CPU0_SA_CS_N<3>")
	)
	(arc
		(start 335.44256 -258.478782)
		(mid 335.255362 -258.428639)
		(end 335.068164 -258.478782)
		(width 0.088646)
		(layer "In11.Cu")
		(net "M_D_CPU0_SA_CS_N<3>")
	)
	(arc
		(start 348.412816 -258.80314)
		(mid 348.22042 -258.828802)
		(end 348.041468 -258.903978)
		(width 0.088646)
		(layer "In11.Cu")
		(net "M_D_CPU0_SA_CS_N<3>")
	)
	(arc
		(start 339.767418 -258.478782)
		(mid 339.493189 -258.554707)
		(end 339.216746 -258.487418)
		(width 0.088646)
		(layer "In11.Cu")
		(net "M_D_CPU0_SA_CS_N<3>")
	)
	(arc
		(start 332.62316 -258.478782)
		(mid 332.532904 -258.44106)
		(end 332.435962 -258.427982)
		(width 0.088646)
		(layer "In11.Cu")
		(net "M_D_CPU0_SA_CS_N<3>")
	)
	(arc
		(start 336.007964 -258.478782)
		(mid 335.725262 -258.554524)
		(end 335.44256 -258.478782)
		(width 0.088646)
		(layer "In11.Cu")
		(net "M_D_CPU0_SA_CS_N<3>")
	)
	(arc
		(start 347.660214 -259.127498)
		(mid 347.473016 -259.177641)
		(end 347.285818 -259.127498)
		(width 0.088646)
		(layer "In11.Cu")
		(net "M_D_CPU0_SA_CS_N<3>")
	)
	(arc
		(start 340.141814 -258.478782)
		(mid 339.954616 -258.428639)
		(end 339.767418 -258.478782)
		(width 0.088646)
		(layer "In11.Cu")
		(net "M_D_CPU0_SA_CS_N<3>")
	)
	(segment
		(start 264.729214 -267.866622)
		(end 263.624314 -267.866622)
		(width 0.20066)
		(layer "F.Cu")
		(net "M_D_CPU0_SA_CS_N<2>")
	)
	(segment
		(start 347.942916 -259.616702)
		(end 347.942662 -259.616956)
		(width 0.20066)
		(layer "F.Cu")
		(net "M_D_CPU0_SA_CS_N<2>")
	)
	(segment
		(start 347.942916 -259.081016)
		(end 347.942916 -259.616702)
		(width 0.20066)
		(layer "F.Cu")
		(net "M_D_CPU0_SA_CS_N<2>")
	)
	(segment
		(start 268.070584 -268.238986)
		(end 268.070584 -268.15796)
		(width 0.18288)
		(layer "In11.Cu")
		(net "M_D_CPU0_SA_CS_N<2>")
	)
	(segment
		(start 313.708034 -263.250426)
		(end 313.123834 -263.834626)
		(width 0.18288)
		(layer "In11.Cu")
		(net "M_D_CPU0_SA_CS_N<2>")
	)
	(segment
		(start 301.615602 -265.637518)
		(end 301.615602 -265.44143)
		(width 0.18288)
		(layer "In11.Cu")
		(net "M_D_CPU0_SA_CS_N<2>")
	)
	(segment
		(start 268.070584 -268.15796)
		(end 267.877544 -267.96492)
		(width 0.18288)
		(layer "In11.Cu")
		(net "M_D_CPU0_SA_CS_N<2>")
	)
	(segment
		(start 281.138122 -266.611354)
		(end 280.267918 -265.74115)
		(width 0.18288)
		(layer "In11.Cu")
		(net "M_D_CPU0_SA_CS_N<2>")
	)
	(segment
		(start 283.164534 -265.74115)
		(end 282.29433 -266.611354)
		(width 0.18288)
		(layer "In11.Cu")
		(net "M_D_CPU0_SA_CS_N<2>")
	)
	(segment
		(start 292.03777 -265.587226)
		(end 288.35096 -265.587226)
		(width 0.18288)
		(layer "In11.Cu")
		(net "M_D_CPU0_SA_CS_N<2>")
	)
	(segment
		(start 278.069294 -265.892026)
		(end 277.404322 -265.892026)
		(width 0.18288)
		(layer "In11.Cu")
		(net "M_D_CPU0_SA_CS_N<2>")
	)
	(segment
		(start 276.596094 -265.561826)
		(end 275.249894 -266.146026)
		(width 0.18288)
		(layer "In11.Cu")
		(net "M_D_CPU0_SA_CS_N<2>")
	)
	(segment
		(start 286.190182 -265.253724)
		(end 285.997142 -265.446764)
		(width 0.18288)
		(layer "In11.Cu")
		(net "M_D_CPU0_SA_CS_N<2>")
	)
	(segment
		(start 267.369544 -268.238986)
		(end 267.176504 -268.432026)
		(width 0.18288)
		(layer "In11.Cu")
		(net "M_D_CPU0_SA_CS_N<2>")
	)
	(segment
		(start 319.92951 -261.03453)
		(end 319.804034 -261.03453)
		(width 0.18288)
		(layer "In11.Cu")
		(net "M_D_CPU0_SA_CS_N<2>")
	)
	(segment
		(start 332.03642 -259.203444)
		(end 331.766164 -258.933188)
		(width 0.088646)
		(layer "In11.Cu")
		(net "M_D_CPU0_SA_CS_N<2>")
	)
	(segment
		(start 345.876118 -259.941314)
		(end 345.58986 -259.775706)
		(width 0.088646)
		(layer "In11.Cu")
		(net "M_D_CPU0_SA_CS_N<2>")
	)
	(segment
		(start 340.237064 -259.292598)
		(end 340.22665 -259.298694)
		(width 0.088646)
		(layer "In11.Cu")
		(net "M_D_CPU0_SA_CS_N<2>")
	)
	(segment
		(start 267.176504 -268.432026)
		(end 265.294618 -268.432026)
		(width 0.18288)
		(layer "In11.Cu")
		(net "M_D_CPU0_SA_CS_N<2>")
	)
	(segment
		(start 301.808642 -265.830558)
		(end 301.615602 -265.637518)
		(width 0.18288)
		(layer "In11.Cu")
		(net "M_D_CPU0_SA_CS_N<2>")
	)
	(segment
		(start 286.891222 -265.886692)
		(end 286.698182 -265.693652)
		(width 0.18288)
		(layer "In11.Cu")
		(net "M_D_CPU0_SA_CS_N<2>")
	)
	(segment
		(start 341.176864 -259.292598)
		(end 341.162132 -259.301234)
		(width 0.088646)
		(layer "In11.Cu")
		(net "M_D_CPU0_SA_CS_N<2>")
	)
	(segment
		(start 307.215794 -264.723626)
		(end 306.913534 -265.025886)
		(width 0.18288)
		(layer "In11.Cu")
		(net "M_D_CPU0_SA_CS_N<2>")
	)
	(segment
		(start 314.45454 -263.250426)
		(end 313.708034 -263.250426)
		(width 0.18288)
		(layer "In11.Cu")
		(net "M_D_CPU0_SA_CS_N<2>")
	)
	(segment
		(start 296.450004 -265.632692)
		(end 296.341546 -265.74115)
		(width 0.18288)
		(layer "In11.Cu")
		(net "M_D_CPU0_SA_CS_N<2>")
	)
	(segment
		(start 267.562584 -267.96492)
		(end 267.369544 -268.15796)
		(width 0.18288)
		(layer "In11.Cu")
		(net "M_D_CPU0_SA_CS_N<2>")
	)
	(segment
		(start 288.051494 -265.886692)
		(end 286.891222 -265.886692)
		(width 0.18288)
		(layer "In11.Cu")
		(net "M_D_CPU0_SA_CS_N<2>")
	)
	(segment
		(start 342.116664 -259.292598)
		(end 342.101932 -259.301234)
		(width 0.088646)
		(layer "In11.Cu")
		(net "M_D_CPU0_SA_CS_N<2>")
	)
	(segment
		(start 300.718982 -265.830558)
		(end 299.824902 -265.830558)
		(width 0.18288)
		(layer "In11.Cu")
		(net "M_D_CPU0_SA_CS_N<2>")
	)
	(segment
		(start 273.751294 -266.679426)
		(end 272.98777 -267.44295)
		(width 0.18288)
		(layer "In11.Cu")
		(net "M_D_CPU0_SA_CS_N<2>")
	)
	(segment
		(start 344.936064 -259.292598)
		(end 344.921332 -259.301234)
		(width 0.088646)
		(layer "In11.Cu")
		(net "M_D_CPU0_SA_CS_N<2>")
	)
	(segment
		(start 301.422562 -265.24839)
		(end 301.105062 -265.24839)
		(width 0.18288)
		(layer "In11.Cu")
		(net "M_D_CPU0_SA_CS_N<2>")
	)
	(segment
		(start 267.877544 -267.96492)
		(end 267.562584 -267.96492)
		(width 0.18288)
		(layer "In11.Cu")
		(net "M_D_CPU0_SA_CS_N<2>")
	)
	(segment
		(start 346.260928 -259.935218)
		(end 346.250514 -259.941314)
		(width 0.088646)
		(layer "In11.Cu")
		(net "M_D_CPU0_SA_CS_N<2>")
	)
	(segment
		(start 306.913534 -265.025886)
		(end 303.816766 -265.025886)
		(width 0.18288)
		(layer "In11.Cu")
		(net "M_D_CPU0_SA_CS_N<2>")
	)
	(segment
		(start 286.505142 -265.253724)
		(end 286.190182 -265.253724)
		(width 0.18288)
		(layer "In11.Cu")
		(net "M_D_CPU0_SA_CS_N<2>")
	)
	(segment
		(start 284.597094 -265.74115)
		(end 283.164534 -265.74115)
		(width 0.18288)
		(layer "In11.Cu")
		(net "M_D_CPU0_SA_CS_N<2>")
	)
	(segment
		(start 269.887954 -269.219426)
		(end 269.100554 -268.432026)
		(width 0.18288)
		(layer "In11.Cu")
		(net "M_D_CPU0_SA_CS_N<2>")
	)
	(segment
		(start 272.98777 -267.44295)
		(end 271.973802 -267.44295)
		(width 0.18288)
		(layer "In11.Cu")
		(net "M_D_CPU0_SA_CS_N<2>")
	)
	(segment
		(start 284.742636 -265.886692)
		(end 284.597094 -265.74115)
		(width 0.18288)
		(layer "In11.Cu")
		(net "M_D_CPU0_SA_CS_N<2>")
	)
	(segment
		(start 343.996264 -259.292598)
		(end 343.981532 -259.301234)
		(width 0.088646)
		(layer "In11.Cu")
		(net "M_D_CPU0_SA_CS_N<2>")
	)
	(segment
		(start 330.927202 -258.933188)
		(end 330.007722 -258.933188)
		(width 0.18288)
		(layer "In11.Cu")
		(net "M_D_CPU0_SA_CS_N<2>")
	)
	(segment
		(start 310.763158 -264.723626)
		(end 307.215794 -264.723626)
		(width 0.18288)
		(layer "In11.Cu")
		(net "M_D_CPU0_SA_CS_N<2>")
	)
	(segment
		(start 277.404322 -265.892026)
		(end 277.074122 -265.561826)
		(width 0.18288)
		(layer "In11.Cu")
		(net "M_D_CPU0_SA_CS_N<2>")
	)
	(segment
		(start 300.912022 -265.44143)
		(end 300.912022 -265.637518)
		(width 0.18288)
		(layer "In11.Cu")
		(net "M_D_CPU0_SA_CS_N<2>")
	)
	(segment
		(start 303.816766 -265.025886)
		(end 303.012094 -265.830558)
		(width 0.18288)
		(layer "In11.Cu")
		(net "M_D_CPU0_SA_CS_N<2>")
	)
	(segment
		(start 321.55257 -259.41147)
		(end 319.92951 -261.03453)
		(width 0.18288)
		(layer "In11.Cu")
		(net "M_D_CPU0_SA_CS_N<2>")
	)
	(segment
		(start 301.105062 -265.24839)
		(end 300.912022 -265.44143)
		(width 0.18288)
		(layer "In11.Cu")
		(net "M_D_CPU0_SA_CS_N<2>")
	)
	(segment
		(start 265.294618 -268.432026)
		(end 264.729214 -267.866622)
		(width 0.18288)
		(layer "In11.Cu")
		(net "M_D_CPU0_SA_CS_N<2>")
	)
	(segment
		(start 285.997142 -265.446764)
		(end 285.997142 -265.693652)
		(width 0.18288)
		(layer "In11.Cu")
		(net "M_D_CPU0_SA_CS_N<2>")
	)
	(segment
		(start 280.267918 -265.74115)
		(end 278.22017 -265.74115)
		(width 0.18288)
		(layer "In11.Cu")
		(net "M_D_CPU0_SA_CS_N<2>")
	)
	(segment
		(start 271.973802 -267.44295)
		(end 270.197326 -269.219426)
		(width 0.18288)
		(layer "In11.Cu")
		(net "M_D_CPU0_SA_CS_N<2>")
	)
	(segment
		(start 299.735494 -265.74115)
		(end 297.195494 -265.74115)
		(width 0.18288)
		(layer "In11.Cu")
		(net "M_D_CPU0_SA_CS_N<2>")
	)
	(segment
		(start 267.369544 -268.15796)
		(end 267.369544 -268.238986)
		(width 0.18288)
		(layer "In11.Cu")
		(net "M_D_CPU0_SA_CS_N<2>")
	)
	(segment
		(start 293.28237 -265.74115)
		(end 293.210996 -265.812524)
		(width 0.18288)
		(layer "In11.Cu")
		(net "M_D_CPU0_SA_CS_N<2>")
	)
	(segment
		(start 330.007722 -258.933188)
		(end 329.52944 -259.41147)
		(width 0.18288)
		(layer "In11.Cu")
		(net "M_D_CPU0_SA_CS_N<2>")
	)
	(segment
		(start 300.912022 -265.637518)
		(end 300.718982 -265.830558)
		(width 0.18288)
		(layer "In11.Cu")
		(net "M_D_CPU0_SA_CS_N<2>")
	)
	(segment
		(start 303.012094 -265.830558)
		(end 301.808642 -265.830558)
		(width 0.18288)
		(layer "In11.Cu")
		(net "M_D_CPU0_SA_CS_N<2>")
	)
	(segment
		(start 269.100554 -268.432026)
		(end 268.263624 -268.432026)
		(width 0.18288)
		(layer "In11.Cu")
		(net "M_D_CPU0_SA_CS_N<2>")
	)
	(segment
		(start 301.615602 -265.44143)
		(end 301.422562 -265.24839)
		(width 0.18288)
		(layer "In11.Cu")
		(net "M_D_CPU0_SA_CS_N<2>")
	)
	(segment
		(start 288.35096 -265.587226)
		(end 288.051494 -265.886692)
		(width 0.18288)
		(layer "In11.Cu")
		(net "M_D_CPU0_SA_CS_N<2>")
	)
	(segment
		(start 275.249894 -266.146026)
		(end 274.183094 -266.679426)
		(width 0.18288)
		(layer "In11.Cu")
		(net "M_D_CPU0_SA_CS_N<2>")
	)
	(segment
		(start 345.310714 -259.292852)
		(end 345.31046 -259.292598)
		(width 0.088646)
		(layer "In11.Cu")
		(net "M_D_CPU0_SA_CS_N<2>")
	)
	(segment
		(start 347.587062 -259.712206)
		(end 347.19006 -259.941314)
		(width 0.088646)
		(layer "In11.Cu")
		(net "M_D_CPU0_SA_CS_N<2>")
	)
	(segment
		(start 329.52944 -259.41147)
		(end 321.55257 -259.41147)
		(width 0.18288)
		(layer "In11.Cu")
		(net "M_D_CPU0_SA_CS_N<2>")
	)
	(segment
		(start 297.195494 -265.74115)
		(end 297.087036 -265.632692)
		(width 0.18288)
		(layer "In11.Cu")
		(net "M_D_CPU0_SA_CS_N<2>")
	)
	(segment
		(start 282.29433 -266.611354)
		(end 281.138122 -266.611354)
		(width 0.18288)
		(layer "In11.Cu")
		(net "M_D_CPU0_SA_CS_N<2>")
	)
	(segment
		(start 285.997142 -265.693652)
		(end 285.804102 -265.886692)
		(width 0.18288)
		(layer "In11.Cu")
		(net "M_D_CPU0_SA_CS_N<2>")
	)
	(segment
		(start 299.824902 -265.830558)
		(end 299.735494 -265.74115)
		(width 0.18288)
		(layer "In11.Cu")
		(net "M_D_CPU0_SA_CS_N<2>")
	)
	(segment
		(start 311.652158 -263.834626)
		(end 310.763158 -264.723626)
		(width 0.18288)
		(layer "In11.Cu")
		(net "M_D_CPU0_SA_CS_N<2>")
	)
	(segment
		(start 286.698182 -265.693652)
		(end 286.698182 -265.446764)
		(width 0.18288)
		(layer "In11.Cu")
		(net "M_D_CPU0_SA_CS_N<2>")
	)
	(segment
		(start 319.804034 -261.03453)
		(end 314.45454 -263.250426)
		(width 0.18288)
		(layer "In11.Cu")
		(net "M_D_CPU0_SA_CS_N<2>")
	)
	(segment
		(start 297.087036 -265.632692)
		(end 296.450004 -265.632692)
		(width 0.18288)
		(layer "In11.Cu")
		(net "M_D_CPU0_SA_CS_N<2>")
	)
	(segment
		(start 331.766164 -258.933188)
		(end 330.927202 -258.933188)
		(width 0.088646)
		(layer "In11.Cu")
		(net "M_D_CPU0_SA_CS_N<2>")
	)
	(segment
		(start 293.210996 -265.812524)
		(end 292.263068 -265.812524)
		(width 0.18288)
		(layer "In11.Cu")
		(net "M_D_CPU0_SA_CS_N<2>")
	)
	(segment
		(start 285.804102 -265.886692)
		(end 284.742636 -265.886692)
		(width 0.18288)
		(layer "In11.Cu")
		(net "M_D_CPU0_SA_CS_N<2>")
	)
	(segment
		(start 278.22017 -265.74115)
		(end 278.069294 -265.892026)
		(width 0.18288)
		(layer "In11.Cu")
		(net "M_D_CPU0_SA_CS_N<2>")
	)
	(segment
		(start 313.123834 -263.834626)
		(end 311.652158 -263.834626)
		(width 0.18288)
		(layer "In11.Cu")
		(net "M_D_CPU0_SA_CS_N<2>")
	)
	(segment
		(start 286.698182 -265.446764)
		(end 286.505142 -265.253724)
		(width 0.18288)
		(layer "In11.Cu")
		(net "M_D_CPU0_SA_CS_N<2>")
	)
	(segment
		(start 296.341546 -265.74115)
		(end 293.28237 -265.74115)
		(width 0.18288)
		(layer "In11.Cu")
		(net "M_D_CPU0_SA_CS_N<2>")
	)
	(segment
		(start 277.074122 -265.561826)
		(end 276.596094 -265.561826)
		(width 0.18288)
		(layer "In11.Cu")
		(net "M_D_CPU0_SA_CS_N<2>")
	)
	(segment
		(start 268.263624 -268.432026)
		(end 268.070584 -268.238986)
		(width 0.18288)
		(layer "In11.Cu")
		(net "M_D_CPU0_SA_CS_N<2>")
	)
	(segment
		(start 339.297518 -259.292598)
		(end 339.287104 -259.298694)
		(width 0.088646)
		(layer "In11.Cu")
		(net "M_D_CPU0_SA_CS_N<2>")
	)
	(segment
		(start 274.183094 -266.679426)
		(end 273.751294 -266.679426)
		(width 0.18288)
		(layer "In11.Cu")
		(net "M_D_CPU0_SA_CS_N<2>")
	)
	(segment
		(start 292.263068 -265.812524)
		(end 292.03777 -265.587226)
		(width 0.18288)
		(layer "In11.Cu")
		(net "M_D_CPU0_SA_CS_N<2>")
	)
	(segment
		(start 270.197326 -269.219426)
		(end 269.887954 -269.219426)
		(width 0.18288)
		(layer "In11.Cu")
		(net "M_D_CPU0_SA_CS_N<2>")
	)
	(arc
		(start 333.658464 -259.292598)
		(mid 333.375762 -259.368374)
		(end 333.09306 -259.292598)
		(width 0.088646)
		(layer "In11.Cu")
		(net "M_D_CPU0_SA_CS_N<2>")
	)
	(arc
		(start 334.598264 -259.292598)
		(mid 334.315562 -259.368374)
		(end 334.03286 -259.292598)
		(width 0.088646)
		(layer "In11.Cu")
		(net "M_D_CPU0_SA_CS_N<2>")
	)
	(arc
		(start 336.477864 -259.292598)
		(mid 336.195162 -259.368374)
		(end 335.91246 -259.292598)
		(width 0.088646)
		(layer "In11.Cu")
		(net "M_D_CPU0_SA_CS_N<2>")
	)
	(arc
		(start 333.09306 -259.292598)
		(mid 332.905862 -259.242455)
		(end 332.718664 -259.292598)
		(width 0.088646)
		(layer "In11.Cu")
		(net "M_D_CPU0_SA_CS_N<2>")
	)
	(arc
		(start 347.942662 -259.616956)
		(mid 347.758593 -259.64118)
		(end 347.587062 -259.712206)
		(width 0.088646)
		(layer "In11.Cu")
		(net "M_D_CPU0_SA_CS_N<2>")
	)
	(arc
		(start 345.58986 -259.775706)
		(mid 345.522594 -259.708658)
		(end 345.497912 -259.616956)
		(width 0.088646)
		(layer "In11.Cu")
		(net "M_D_CPU0_SA_CS_N<2>")
	)
	(arc
		(start 339.671914 -259.292598)
		(mid 339.484716 -259.242455)
		(end 339.297518 -259.292598)
		(width 0.088646)
		(layer "In11.Cu")
		(net "M_D_CPU0_SA_CS_N<2>")
	)
	(arc
		(start 344.921332 -259.301234)
		(mid 344.644857 -259.368554)
		(end 344.37066 -259.292598)
		(width 0.088646)
		(layer "In11.Cu")
		(net "M_D_CPU0_SA_CS_N<2>")
	)
	(arc
		(start 341.55126 -259.292598)
		(mid 341.364062 -259.242455)
		(end 341.176864 -259.292598)
		(width 0.088646)
		(layer "In11.Cu")
		(net "M_D_CPU0_SA_CS_N<2>")
	)
	(arc
		(start 334.03286 -259.292598)
		(mid 333.845662 -259.242455)
		(end 333.658464 -259.292598)
		(width 0.088646)
		(layer "In11.Cu")
		(net "M_D_CPU0_SA_CS_N<2>")
	)
	(arc
		(start 338.73186 -259.292598)
		(mid 338.544662 -259.242455)
		(end 338.357464 -259.292598)
		(width 0.088646)
		(layer "In11.Cu")
		(net "M_D_CPU0_SA_CS_N<2>")
	)
	(arc
		(start 342.49106 -259.292598)
		(mid 342.303862 -259.242455)
		(end 342.116664 -259.292598)
		(width 0.088646)
		(layer "In11.Cu")
		(net "M_D_CPU0_SA_CS_N<2>")
	)
	(arc
		(start 340.22665 -259.298694)
		(mid 339.948472 -259.368417)
		(end 339.671914 -259.292598)
		(width 0.088646)
		(layer "In11.Cu")
		(net "M_D_CPU0_SA_CS_N<2>")
	)
	(arc
		(start 343.43086 -259.292598)
		(mid 343.243662 -259.242455)
		(end 343.056464 -259.292598)
		(width 0.088646)
		(layer "In11.Cu")
		(net "M_D_CPU0_SA_CS_N<2>")
	)
	(arc
		(start 335.91246 -259.292598)
		(mid 335.725262 -259.242455)
		(end 335.538064 -259.292598)
		(width 0.088646)
		(layer "In11.Cu")
		(net "M_D_CPU0_SA_CS_N<2>")
	)
	(arc
		(start 346.815664 -259.941314)
		(mid 346.539105 -259.865571)
		(end 346.260928 -259.935218)
		(width 0.088646)
		(layer "In11.Cu")
		(net "M_D_CPU0_SA_CS_N<2>")
	)
	(arc
		(start 335.538064 -259.292598)
		(mid 335.255362 -259.368374)
		(end 334.97266 -259.292598)
		(width 0.088646)
		(layer "In11.Cu")
		(net "M_D_CPU0_SA_CS_N<2>")
	)
	(arc
		(start 345.31046 -259.292598)
		(mid 345.123262 -259.242455)
		(end 344.936064 -259.292598)
		(width 0.088646)
		(layer "In11.Cu")
		(net "M_D_CPU0_SA_CS_N<2>")
	)
	(arc
		(start 337.417664 -259.292598)
		(mid 337.134962 -259.368374)
		(end 336.85226 -259.292598)
		(width 0.088646)
		(layer "In11.Cu")
		(net "M_D_CPU0_SA_CS_N<2>")
	)
	(arc
		(start 334.97266 -259.292598)
		(mid 334.785462 -259.242455)
		(end 334.598264 -259.292598)
		(width 0.088646)
		(layer "In11.Cu")
		(net "M_D_CPU0_SA_CS_N<2>")
	)
	(arc
		(start 343.981532 -259.301234)
		(mid 343.705057 -259.368554)
		(end 343.43086 -259.292598)
		(width 0.088646)
		(layer "In11.Cu")
		(net "M_D_CPU0_SA_CS_N<2>")
	)
	(arc
		(start 332.15326 -259.292598)
		(mid 332.12039 -259.272108)
		(end 332.088998 -259.249418)
		(width 0.088646)
		(layer "In11.Cu")
		(net "M_D_CPU0_SA_CS_N<2>")
	)
	(arc
		(start 347.19006 -259.941314)
		(mid 347.002862 -259.991457)
		(end 346.815664 -259.941314)
		(width 0.088646)
		(layer "In11.Cu")
		(net "M_D_CPU0_SA_CS_N<2>")
	)
	(arc
		(start 332.088998 -259.249418)
		(mid 332.061999 -259.227243)
		(end 332.03642 -259.203444)
		(width 0.088646)
		(layer "In11.Cu")
		(net "M_D_CPU0_SA_CS_N<2>")
	)
	(arc
		(start 343.056464 -259.292598)
		(mid 342.773762 -259.368374)
		(end 342.49106 -259.292598)
		(width 0.088646)
		(layer "In11.Cu")
		(net "M_D_CPU0_SA_CS_N<2>")
	)
	(arc
		(start 339.287104 -259.298694)
		(mid 339.008672 -259.36854)
		(end 338.73186 -259.292598)
		(width 0.088646)
		(layer "In11.Cu")
		(net "M_D_CPU0_SA_CS_N<2>")
	)
	(arc
		(start 344.37066 -259.292598)
		(mid 344.183462 -259.242455)
		(end 343.996264 -259.292598)
		(width 0.088646)
		(layer "In11.Cu")
		(net "M_D_CPU0_SA_CS_N<2>")
	)
	(arc
		(start 342.101932 -259.301234)
		(mid 341.825457 -259.368554)
		(end 341.55126 -259.292598)
		(width 0.088646)
		(layer "In11.Cu")
		(net "M_D_CPU0_SA_CS_N<2>")
	)
	(arc
		(start 345.497912 -259.616956)
		(mid 345.447748 -259.429818)
		(end 345.310714 -259.292852)
		(width 0.088646)
		(layer "In11.Cu")
		(net "M_D_CPU0_SA_CS_N<2>")
	)
	(arc
		(start 341.162132 -259.301234)
		(mid 340.885657 -259.368554)
		(end 340.61146 -259.292598)
		(width 0.088646)
		(layer "In11.Cu")
		(net "M_D_CPU0_SA_CS_N<2>")
	)
	(arc
		(start 336.85226 -259.292598)
		(mid 336.665062 -259.242455)
		(end 336.477864 -259.292598)
		(width 0.088646)
		(layer "In11.Cu")
		(net "M_D_CPU0_SA_CS_N<2>")
	)
	(arc
		(start 340.61146 -259.292598)
		(mid 340.424262 -259.242455)
		(end 340.237064 -259.292598)
		(width 0.088646)
		(layer "In11.Cu")
		(net "M_D_CPU0_SA_CS_N<2>")
	)
	(arc
		(start 346.250514 -259.941314)
		(mid 346.063316 -259.991457)
		(end 345.876118 -259.941314)
		(width 0.088646)
		(layer "In11.Cu")
		(net "M_D_CPU0_SA_CS_N<2>")
	)
	(arc
		(start 337.79206 -259.292598)
		(mid 337.604862 -259.242455)
		(end 337.417664 -259.292598)
		(width 0.088646)
		(layer "In11.Cu")
		(net "M_D_CPU0_SA_CS_N<2>")
	)
	(arc
		(start 338.357464 -259.292598)
		(mid 338.074762 -259.368374)
		(end 337.79206 -259.292598)
		(width 0.088646)
		(layer "In11.Cu")
		(net "M_D_CPU0_SA_CS_N<2>")
	)
	(arc
		(start 332.718664 -259.292598)
		(mid 332.435962 -259.368374)
		(end 332.15326 -259.292598)
		(width 0.088646)
		(layer "In11.Cu")
		(net "M_D_CPU0_SA_CS_N<2>")
	)
	(segment
		(start 346.532962 -258.802886)
		(end 346.533216 -258.80314)
		(width 0.20066)
		(layer "F.Cu")
		(net "M_D_CPU0_SA_CS_N<1>")
	)
	(segment
		(start 346.532962 -258.2672)
		(end 346.532962 -258.802886)
		(width 0.20066)
		(layer "F.Cu")
		(net "M_D_CPU0_SA_CS_N<1>")
	)
	(segment
		(start 261.285482 -267.016738)
		(end 260.180582 -267.016738)
		(width 0.20066)
		(layer "F.Cu")
		(net "M_D_CPU0_SA_CS_N<1>")
	)
	(segment
		(start 332.435962 -258.237736)
		(end 332.139036 -258.237736)
		(width 0.088646)
		(layer "In11.Cu")
		(net "M_D_CPU0_SA_CS_N<1>")
	)
	(segment
		(start 263.938766 -266.592812)
		(end 263.745726 -266.399772)
		(width 0.18288)
		(layer "In11.Cu")
		(net "M_D_CPU0_SA_CS_N<1>")
	)
	(segment
		(start 346.533216 -258.80314)
		(end 345.905328 -258.330446)
		(width 0.088646)
		(layer "In11.Cu")
		(net "M_D_CPU0_SA_CS_N<1>")
	)
	(segment
		(start 275.173186 -263.860026)
		(end 273.952462 -263.860026)
		(width 0.18288)
		(layer "In11.Cu")
		(net "M_D_CPU0_SA_CS_N<1>")
	)
	(segment
		(start 345.875864 -258.313682)
		(end 345.875102 -258.313428)
		(width 0.088646)
		(layer "In11.Cu")
		(net "M_D_CPU0_SA_CS_N<1>")
	)
	(segment
		(start 262.851646 -266.563856)
		(end 261.738364 -266.563856)
		(width 0.18288)
		(layer "In11.Cu")
		(net "M_D_CPU0_SA_CS_N<1>")
	)
	(segment
		(start 282.476194 -263.834626)
		(end 281.068018 -263.834626)
		(width 0.18288)
		(layer "In11.Cu")
		(net "M_D_CPU0_SA_CS_N<1>")
	)
	(segment
		(start 288.519362 -263.440672)
		(end 288.137346 -263.058656)
		(width 0.18288)
		(layer "In11.Cu")
		(net "M_D_CPU0_SA_CS_N<1>")
	)
	(segment
		(start 277.278592 -263.068054)
		(end 277.144226 -263.20242)
		(width 0.18288)
		(layer "In11.Cu")
		(net "M_D_CPU0_SA_CS_N<1>")
	)
	(segment
		(start 309.038244 -261.914386)
		(end 308.723284 -261.914386)
		(width 0.18288)
		(layer "In11.Cu")
		(net "M_D_CPU0_SA_CS_N<1>")
	)
	(segment
		(start 269.379192 -266.381484)
		(end 269.167864 -266.592812)
		(width 0.18288)
		(layer "In11.Cu")
		(net "M_D_CPU0_SA_CS_N<1>")
	)
	(segment
		(start 273.037808 -264.77468)
		(end 272.06702 -264.77468)
		(width 0.18288)
		(layer "In11.Cu")
		(net "M_D_CPU0_SA_CS_N<1>")
	)
	(segment
		(start 299.732446 -263.041892)
		(end 299.583094 -263.191244)
		(width 0.18288)
		(layer "In11.Cu")
		(net "M_D_CPU0_SA_CS_N<1>")
	)
	(segment
		(start 312.675524 -261.5692)
		(end 311.32272 -261.5692)
		(width 0.18288)
		(layer "In11.Cu")
		(net "M_D_CPU0_SA_CS_N<1>")
	)
	(segment
		(start 308.337204 -262.437626)
		(end 306.974494 -262.437626)
		(width 0.18288)
		(layer "In11.Cu")
		(net "M_D_CPU0_SA_CS_N<1>")
	)
	(segment
		(start 272.06702 -264.77468)
		(end 270.460216 -266.381484)
		(width 0.18288)
		(layer "In11.Cu")
		(net "M_D_CPU0_SA_CS_N<1>")
	)
	(segment
		(start 304.97653 -262.328914)
		(end 303.730406 -262.328914)
		(width 0.18288)
		(layer "In11.Cu")
		(net "M_D_CPU0_SA_CS_N<1>")
	)
	(segment
		(start 331.771498 -257.870198)
		(end 330.927202 -257.870198)
		(width 0.088646)
		(layer "In11.Cu")
		(net "M_D_CPU0_SA_CS_N<1>")
	)
	(segment
		(start 345.905328 -258.330446)
		(end 345.875864 -258.313682)
		(width 0.088646)
		(layer "In11.Cu")
		(net "M_D_CPU0_SA_CS_N<1>")
	)
	(segment
		(start 261.738364 -266.563856)
		(end 261.285482 -267.016738)
		(width 0.18288)
		(layer "In11.Cu")
		(net "M_D_CPU0_SA_CS_N<1>")
	)
	(segment
		(start 284.985206 -263.058656)
		(end 284.852872 -263.19099)
		(width 0.18288)
		(layer "In11.Cu")
		(net "M_D_CPU0_SA_CS_N<1>")
	)
	(segment
		(start 305.87061 -262.521954)
		(end 305.87061 -262.744712)
		(width 0.18288)
		(layer "In11.Cu")
		(net "M_D_CPU0_SA_CS_N<1>")
	)
	(segment
		(start 263.745726 -266.399772)
		(end 263.745726 -265.594592)
		(width 0.18288)
		(layer "In11.Cu")
		(net "M_D_CPU0_SA_CS_N<1>")
	)
	(segment
		(start 329.113642 -258.360672)
		(end 320.759328 -258.360672)
		(width 0.18288)
		(layer "In11.Cu")
		(net "M_D_CPU0_SA_CS_N<1>")
	)
	(segment
		(start 343.996264 -258.313428)
		(end 343.981532 -258.304792)
		(width 0.088646)
		(layer "In11.Cu")
		(net "M_D_CPU0_SA_CS_N<1>")
	)
	(segment
		(start 305.67757 -262.937752)
		(end 305.36261 -262.937752)
		(width 0.18288)
		(layer "In11.Cu")
		(net "M_D_CPU0_SA_CS_N<1>")
	)
	(segment
		(start 308.530244 -262.244586)
		(end 308.337204 -262.437626)
		(width 0.18288)
		(layer "In11.Cu")
		(net "M_D_CPU0_SA_CS_N<1>")
	)
	(segment
		(start 263.745726 -265.594592)
		(end 263.552686 -265.401552)
		(width 0.18288)
		(layer "In11.Cu")
		(net "M_D_CPU0_SA_CS_N<1>")
	)
	(segment
		(start 263.044686 -266.370816)
		(end 262.851646 -266.563856)
		(width 0.18288)
		(layer "In11.Cu")
		(net "M_D_CPU0_SA_CS_N<1>")
	)
	(segment
		(start 273.952462 -263.860026)
		(end 273.037808 -264.77468)
		(width 0.18288)
		(layer "In11.Cu")
		(net "M_D_CPU0_SA_CS_N<1>")
	)
	(segment
		(start 303.017428 -263.041892)
		(end 299.732446 -263.041892)
		(width 0.18288)
		(layer "In11.Cu")
		(net "M_D_CPU0_SA_CS_N<1>")
	)
	(segment
		(start 342.116664 -258.313428)
		(end 342.101932 -258.304792)
		(width 0.088646)
		(layer "In11.Cu")
		(net "M_D_CPU0_SA_CS_N<1>")
	)
	(segment
		(start 308.723284 -261.914386)
		(end 308.530244 -262.107426)
		(width 0.18288)
		(layer "In11.Cu")
		(net "M_D_CPU0_SA_CS_N<1>")
	)
	(segment
		(start 283.11983 -263.19099)
		(end 282.476194 -263.834626)
		(width 0.18288)
		(layer "In11.Cu")
		(net "M_D_CPU0_SA_CS_N<1>")
	)
	(segment
		(start 266.036806 -266.592812)
		(end 263.938766 -266.592812)
		(width 0.18288)
		(layer "In11.Cu")
		(net "M_D_CPU0_SA_CS_N<1>")
	)
	(segment
		(start 288.137346 -263.058656)
		(end 286.8041 -263.058656)
		(width 0.18288)
		(layer "In11.Cu")
		(net "M_D_CPU0_SA_CS_N<1>")
	)
	(segment
		(start 306.974494 -262.437626)
		(end 306.865782 -262.328914)
		(width 0.18288)
		(layer "In11.Cu")
		(net "M_D_CPU0_SA_CS_N<1>")
	)
	(segment
		(start 266.203684 -266.75969)
		(end 266.036806 -266.592812)
		(width 0.18288)
		(layer "In11.Cu")
		(net "M_D_CPU0_SA_CS_N<1>")
	)
	(segment
		(start 293.118794 -262.958326)
		(end 292.417754 -262.958326)
		(width 0.18288)
		(layer "In11.Cu")
		(net "M_D_CPU0_SA_CS_N<1>")
	)
	(segment
		(start 299.583094 -263.191244)
		(end 297.508676 -263.191244)
		(width 0.18288)
		(layer "In11.Cu")
		(net "M_D_CPU0_SA_CS_N<1>")
	)
	(segment
		(start 278.113236 -263.068054)
		(end 277.278592 -263.068054)
		(width 0.18288)
		(layer "In11.Cu")
		(net "M_D_CPU0_SA_CS_N<1>")
	)
	(segment
		(start 339.297264 -258.313428)
		(end 339.28685 -258.307332)
		(width 0.088646)
		(layer "In11.Cu")
		(net "M_D_CPU0_SA_CS_N<1>")
	)
	(segment
		(start 263.044686 -265.594592)
		(end 263.044686 -266.370816)
		(width 0.18288)
		(layer "In11.Cu")
		(net "M_D_CPU0_SA_CS_N<1>")
	)
	(segment
		(start 280.425652 -263.19226)
		(end 278.237442 -263.19226)
		(width 0.18288)
		(layer "In11.Cu")
		(net "M_D_CPU0_SA_CS_N<1>")
	)
	(segment
		(start 277.144226 -263.20242)
		(end 275.830792 -263.20242)
		(width 0.18288)
		(layer "In11.Cu")
		(net "M_D_CPU0_SA_CS_N<1>")
	)
	(segment
		(start 263.552686 -265.401552)
		(end 263.237726 -265.401552)
		(width 0.18288)
		(layer "In11.Cu")
		(net "M_D_CPU0_SA_CS_N<1>")
	)
	(segment
		(start 285.91002 -263.251696)
		(end 285.71698 -263.058656)
		(width 0.18288)
		(layer "In11.Cu")
		(net "M_D_CPU0_SA_CS_N<1>")
	)
	(segment
		(start 286.61106 -263.447276)
		(end 286.41802 -263.640316)
		(width 0.18288)
		(layer "In11.Cu")
		(net "M_D_CPU0_SA_CS_N<1>")
	)
	(segment
		(start 269.167864 -266.592812)
		(end 267.479526 -266.592812)
		(width 0.18288)
		(layer "In11.Cu")
		(net "M_D_CPU0_SA_CS_N<1>")
	)
	(segment
		(start 314.963302 -260.629654)
		(end 313.61507 -260.629654)
		(width 0.18288)
		(layer "In11.Cu")
		(net "M_D_CPU0_SA_CS_N<1>")
	)
	(segment
		(start 293.351712 -263.191244)
		(end 293.118794 -262.958326)
		(width 0.18288)
		(layer "In11.Cu")
		(net "M_D_CPU0_SA_CS_N<1>")
	)
	(segment
		(start 308.530244 -262.107426)
		(end 308.530244 -262.244586)
		(width 0.18288)
		(layer "In11.Cu")
		(net "M_D_CPU0_SA_CS_N<1>")
	)
	(segment
		(start 275.830792 -263.20242)
		(end 275.173186 -263.860026)
		(width 0.18288)
		(layer "In11.Cu")
		(net "M_D_CPU0_SA_CS_N<1>")
	)
	(segment
		(start 286.41802 -263.640316)
		(end 286.10306 -263.640316)
		(width 0.18288)
		(layer "In11.Cu")
		(net "M_D_CPU0_SA_CS_N<1>")
	)
	(segment
		(start 303.730406 -262.328914)
		(end 303.017428 -263.041892)
		(width 0.18288)
		(layer "In11.Cu")
		(net "M_D_CPU0_SA_CS_N<1>")
	)
	(segment
		(start 319.60947 -259.51053)
		(end 316.082426 -259.51053)
		(width 0.18288)
		(layer "In11.Cu")
		(net "M_D_CPU0_SA_CS_N<1>")
	)
	(segment
		(start 332.139036 -258.237736)
		(end 331.771498 -257.870198)
		(width 0.088646)
		(layer "In11.Cu")
		(net "M_D_CPU0_SA_CS_N<1>")
	)
	(segment
		(start 341.176864 -258.313428)
		(end 341.16645 -258.307332)
		(width 0.088646)
		(layer "In11.Cu")
		(net "M_D_CPU0_SA_CS_N<1>")
	)
	(segment
		(start 337.802474 -258.307332)
		(end 337.79206 -258.313428)
		(width 0.088646)
		(layer "In11.Cu")
		(net "M_D_CPU0_SA_CS_N<1>")
	)
	(segment
		(start 329.604116 -257.870198)
		(end 329.113642 -258.360672)
		(width 0.18288)
		(layer "In11.Cu")
		(net "M_D_CPU0_SA_CS_N<1>")
	)
	(segment
		(start 316.082426 -259.51053)
		(end 314.963302 -260.629654)
		(width 0.18288)
		(layer "In11.Cu")
		(net "M_D_CPU0_SA_CS_N<1>")
	)
	(segment
		(start 286.61106 -263.251696)
		(end 286.61106 -263.447276)
		(width 0.18288)
		(layer "In11.Cu")
		(net "M_D_CPU0_SA_CS_N<1>")
	)
	(segment
		(start 305.16957 -262.744712)
		(end 305.16957 -262.521954)
		(width 0.18288)
		(layer "In11.Cu")
		(net "M_D_CPU0_SA_CS_N<1>")
	)
	(segment
		(start 267.312648 -266.75969)
		(end 266.203684 -266.75969)
		(width 0.18288)
		(layer "In11.Cu")
		(net "M_D_CPU0_SA_CS_N<1>")
	)
	(segment
		(start 285.91002 -263.447276)
		(end 285.91002 -263.251696)
		(width 0.18288)
		(layer "In11.Cu")
		(net "M_D_CPU0_SA_CS_N<1>")
	)
	(segment
		(start 313.61507 -260.629654)
		(end 312.675524 -261.5692)
		(width 0.18288)
		(layer "In11.Cu")
		(net "M_D_CPU0_SA_CS_N<1>")
	)
	(segment
		(start 310.454294 -262.437626)
		(end 309.424324 -262.437626)
		(width 0.18288)
		(layer "In11.Cu")
		(net "M_D_CPU0_SA_CS_N<1>")
	)
	(segment
		(start 311.32272 -261.5692)
		(end 310.454294 -262.437626)
		(width 0.18288)
		(layer "In11.Cu")
		(net "M_D_CPU0_SA_CS_N<1>")
	)
	(segment
		(start 278.237442 -263.19226)
		(end 278.113236 -263.068054)
		(width 0.18288)
		(layer "In11.Cu")
		(net "M_D_CPU0_SA_CS_N<1>")
	)
	(segment
		(start 297.373294 -263.326626)
		(end 295.618408 -263.326626)
		(width 0.18288)
		(layer "In11.Cu")
		(net "M_D_CPU0_SA_CS_N<1>")
	)
	(segment
		(start 320.759328 -258.360672)
		(end 319.60947 -259.51053)
		(width 0.18288)
		(layer "In11.Cu")
		(net "M_D_CPU0_SA_CS_N<1>")
	)
	(segment
		(start 309.231284 -262.107426)
		(end 309.038244 -261.914386)
		(width 0.18288)
		(layer "In11.Cu")
		(net "M_D_CPU0_SA_CS_N<1>")
	)
	(segment
		(start 284.852872 -263.19099)
		(end 283.11983 -263.19099)
		(width 0.18288)
		(layer "In11.Cu")
		(net "M_D_CPU0_SA_CS_N<1>")
	)
	(segment
		(start 292.417754 -262.958326)
		(end 291.935408 -263.440672)
		(width 0.18288)
		(layer "In11.Cu")
		(net "M_D_CPU0_SA_CS_N<1>")
	)
	(segment
		(start 295.483026 -263.191244)
		(end 293.351712 -263.191244)
		(width 0.18288)
		(layer "In11.Cu")
		(net "M_D_CPU0_SA_CS_N<1>")
	)
	(segment
		(start 285.71698 -263.058656)
		(end 284.985206 -263.058656)
		(width 0.18288)
		(layer "In11.Cu")
		(net "M_D_CPU0_SA_CS_N<1>")
	)
	(segment
		(start 286.8041 -263.058656)
		(end 286.61106 -263.251696)
		(width 0.18288)
		(layer "In11.Cu")
		(net "M_D_CPU0_SA_CS_N<1>")
	)
	(segment
		(start 340.237318 -258.313428)
		(end 340.226904 -258.307332)
		(width 0.088646)
		(layer "In11.Cu")
		(net "M_D_CPU0_SA_CS_N<1>")
	)
	(segment
		(start 267.479526 -266.592812)
		(end 267.312648 -266.75969)
		(width 0.18288)
		(layer "In11.Cu")
		(net "M_D_CPU0_SA_CS_N<1>")
	)
	(segment
		(start 306.865782 -262.328914)
		(end 306.06365 -262.328914)
		(width 0.18288)
		(layer "In11.Cu")
		(net "M_D_CPU0_SA_CS_N<1>")
	)
	(segment
		(start 309.424324 -262.437626)
		(end 309.231284 -262.244586)
		(width 0.18288)
		(layer "In11.Cu")
		(net "M_D_CPU0_SA_CS_N<1>")
	)
	(segment
		(start 291.935408 -263.440672)
		(end 288.519362 -263.440672)
		(width 0.18288)
		(layer "In11.Cu")
		(net "M_D_CPU0_SA_CS_N<1>")
	)
	(segment
		(start 263.237726 -265.401552)
		(end 263.044686 -265.594592)
		(width 0.18288)
		(layer "In11.Cu")
		(net "M_D_CPU0_SA_CS_N<1>")
	)
	(segment
		(start 305.36261 -262.937752)
		(end 305.16957 -262.744712)
		(width 0.18288)
		(layer "In11.Cu")
		(net "M_D_CPU0_SA_CS_N<1>")
	)
	(segment
		(start 270.460216 -266.381484)
		(end 269.379192 -266.381484)
		(width 0.18288)
		(layer "In11.Cu")
		(net "M_D_CPU0_SA_CS_N<1>")
	)
	(segment
		(start 309.231284 -262.244586)
		(end 309.231284 -262.107426)
		(width 0.18288)
		(layer "In11.Cu")
		(net "M_D_CPU0_SA_CS_N<1>")
	)
	(segment
		(start 286.10306 -263.640316)
		(end 285.91002 -263.447276)
		(width 0.18288)
		(layer "In11.Cu")
		(net "M_D_CPU0_SA_CS_N<1>")
	)
	(segment
		(start 305.16957 -262.521954)
		(end 304.97653 -262.328914)
		(width 0.18288)
		(layer "In11.Cu")
		(net "M_D_CPU0_SA_CS_N<1>")
	)
	(segment
		(start 330.927202 -257.870198)
		(end 329.604116 -257.870198)
		(width 0.18288)
		(layer "In11.Cu")
		(net "M_D_CPU0_SA_CS_N<1>")
	)
	(segment
		(start 306.06365 -262.328914)
		(end 305.87061 -262.521954)
		(width 0.18288)
		(layer "In11.Cu")
		(net "M_D_CPU0_SA_CS_N<1>")
	)
	(segment
		(start 295.618408 -263.326626)
		(end 295.483026 -263.191244)
		(width 0.18288)
		(layer "In11.Cu")
		(net "M_D_CPU0_SA_CS_N<1>")
	)
	(segment
		(start 281.068018 -263.834626)
		(end 280.425652 -263.19226)
		(width 0.18288)
		(layer "In11.Cu")
		(net "M_D_CPU0_SA_CS_N<1>")
	)
	(segment
		(start 344.936318 -258.313428)
		(end 344.925904 -258.307332)
		(width 0.088646)
		(layer "In11.Cu")
		(net "M_D_CPU0_SA_CS_N<1>")
	)
	(segment
		(start 297.508676 -263.191244)
		(end 297.373294 -263.326626)
		(width 0.18288)
		(layer "In11.Cu")
		(net "M_D_CPU0_SA_CS_N<1>")
	)
	(segment
		(start 305.87061 -262.744712)
		(end 305.67757 -262.937752)
		(width 0.18288)
		(layer "In11.Cu")
		(net "M_D_CPU0_SA_CS_N<1>")
	)
	(arc
		(start 343.056464 -258.313428)
		(mid 342.773762 -258.237686)
		(end 342.49106 -258.313428)
		(width 0.088646)
		(layer "In11.Cu")
		(net "M_D_CPU0_SA_CS_N<1>")
	)
	(arc
		(start 340.226904 -258.307332)
		(mid 339.948472 -258.237518)
		(end 339.67166 -258.313428)
		(width 0.088646)
		(layer "In11.Cu")
		(net "M_D_CPU0_SA_CS_N<1>")
	)
	(arc
		(start 332.718664 -258.313428)
		(mid 332.582298 -258.25695)
		(end 332.435962 -258.237736)
		(width 0.088646)
		(layer "In11.Cu")
		(net "M_D_CPU0_SA_CS_N<1>")
	)
	(arc
		(start 344.37066 -258.313428)
		(mid 344.183462 -258.363571)
		(end 343.996264 -258.313428)
		(width 0.088646)
		(layer "In11.Cu")
		(net "M_D_CPU0_SA_CS_N<1>")
	)
	(arc
		(start 338.357718 -258.313428)
		(mid 338.080905 -258.237592)
		(end 337.802474 -258.307332)
		(width 0.088646)
		(layer "In11.Cu")
		(net "M_D_CPU0_SA_CS_N<1>")
	)
	(arc
		(start 337.417664 -258.313428)
		(mid 337.134962 -258.237686)
		(end 336.85226 -258.313428)
		(width 0.088646)
		(layer "In11.Cu")
		(net "M_D_CPU0_SA_CS_N<1>")
	)
	(arc
		(start 343.43086 -258.313428)
		(mid 343.243662 -258.363571)
		(end 343.056464 -258.313428)
		(width 0.088646)
		(layer "In11.Cu")
		(net "M_D_CPU0_SA_CS_N<1>")
	)
	(arc
		(start 343.981532 -258.304792)
		(mid 343.705091 -258.237626)
		(end 343.43086 -258.313428)
		(width 0.088646)
		(layer "In11.Cu")
		(net "M_D_CPU0_SA_CS_N<1>")
	)
	(arc
		(start 335.538064 -258.313428)
		(mid 335.255362 -258.237686)
		(end 334.97266 -258.313428)
		(width 0.088646)
		(layer "In11.Cu")
		(net "M_D_CPU0_SA_CS_N<1>")
	)
	(arc
		(start 339.28685 -258.307332)
		(mid 339.008672 -258.23764)
		(end 338.732114 -258.313428)
		(width 0.088646)
		(layer "In11.Cu")
		(net "M_D_CPU0_SA_CS_N<1>")
	)
	(arc
		(start 345.875102 -258.313428)
		(mid 345.592908 -258.237838)
		(end 345.310714 -258.313428)
		(width 0.088646)
		(layer "In11.Cu")
		(net "M_D_CPU0_SA_CS_N<1>")
	)
	(arc
		(start 334.97266 -258.313428)
		(mid 334.785462 -258.363571)
		(end 334.598264 -258.313428)
		(width 0.088646)
		(layer "In11.Cu")
		(net "M_D_CPU0_SA_CS_N<1>")
	)
	(arc
		(start 336.85226 -258.313428)
		(mid 336.665062 -258.363571)
		(end 336.477864 -258.313428)
		(width 0.088646)
		(layer "In11.Cu")
		(net "M_D_CPU0_SA_CS_N<1>")
	)
	(arc
		(start 335.91246 -258.313428)
		(mid 335.725262 -258.363571)
		(end 335.538064 -258.313428)
		(width 0.088646)
		(layer "In11.Cu")
		(net "M_D_CPU0_SA_CS_N<1>")
	)
	(arc
		(start 334.03286 -258.313428)
		(mid 333.845662 -258.363571)
		(end 333.658464 -258.313428)
		(width 0.088646)
		(layer "In11.Cu")
		(net "M_D_CPU0_SA_CS_N<1>")
	)
	(arc
		(start 336.477864 -258.313428)
		(mid 336.195162 -258.237686)
		(end 335.91246 -258.313428)
		(width 0.088646)
		(layer "In11.Cu")
		(net "M_D_CPU0_SA_CS_N<1>")
	)
	(arc
		(start 341.16645 -258.307332)
		(mid 340.888272 -258.23764)
		(end 340.611714 -258.313428)
		(width 0.088646)
		(layer "In11.Cu")
		(net "M_D_CPU0_SA_CS_N<1>")
	)
	(arc
		(start 341.55126 -258.313428)
		(mid 341.364062 -258.363571)
		(end 341.176864 -258.313428)
		(width 0.088646)
		(layer "In11.Cu")
		(net "M_D_CPU0_SA_CS_N<1>")
	)
	(arc
		(start 334.598264 -258.313428)
		(mid 334.315562 -258.237686)
		(end 334.03286 -258.313428)
		(width 0.088646)
		(layer "In11.Cu")
		(net "M_D_CPU0_SA_CS_N<1>")
	)
	(arc
		(start 340.611714 -258.313428)
		(mid 340.424516 -258.363571)
		(end 340.237318 -258.313428)
		(width 0.088646)
		(layer "In11.Cu")
		(net "M_D_CPU0_SA_CS_N<1>")
	)
	(arc
		(start 344.925904 -258.307332)
		(mid 344.647472 -258.237518)
		(end 344.37066 -258.313428)
		(width 0.088646)
		(layer "In11.Cu")
		(net "M_D_CPU0_SA_CS_N<1>")
	)
	(arc
		(start 339.67166 -258.313428)
		(mid 339.484462 -258.363571)
		(end 339.297264 -258.313428)
		(width 0.088646)
		(layer "In11.Cu")
		(net "M_D_CPU0_SA_CS_N<1>")
	)
	(arc
		(start 333.09306 -258.313428)
		(mid 332.905862 -258.363571)
		(end 332.718664 -258.313428)
		(width 0.088646)
		(layer "In11.Cu")
		(net "M_D_CPU0_SA_CS_N<1>")
	)
	(arc
		(start 342.49106 -258.313428)
		(mid 342.303862 -258.363571)
		(end 342.116664 -258.313428)
		(width 0.088646)
		(layer "In11.Cu")
		(net "M_D_CPU0_SA_CS_N<1>")
	)
	(arc
		(start 338.732114 -258.313428)
		(mid 338.544916 -258.363571)
		(end 338.357718 -258.313428)
		(width 0.088646)
		(layer "In11.Cu")
		(net "M_D_CPU0_SA_CS_N<1>")
	)
	(arc
		(start 333.658464 -258.313428)
		(mid 333.375762 -258.237686)
		(end 333.09306 -258.313428)
		(width 0.088646)
		(layer "In11.Cu")
		(net "M_D_CPU0_SA_CS_N<1>")
	)
	(arc
		(start 342.101932 -258.304792)
		(mid 341.825491 -258.237626)
		(end 341.55126 -258.313428)
		(width 0.088646)
		(layer "In11.Cu")
		(net "M_D_CPU0_SA_CS_N<1>")
	)
	(arc
		(start 337.79206 -258.313428)
		(mid 337.604862 -258.363571)
		(end 337.417664 -258.313428)
		(width 0.088646)
		(layer "In11.Cu")
		(net "M_D_CPU0_SA_CS_N<1>")
	)
	(arc
		(start 345.310714 -258.313428)
		(mid 345.123516 -258.363571)
		(end 344.936318 -258.313428)
		(width 0.088646)
		(layer "In11.Cu")
		(net "M_D_CPU0_SA_CS_N<1>")
	)
	(segment
		(start 257.185414 -267.866622)
		(end 256.080514 -267.866622)
		(width 0.20066)
		(layer "F.Cu")
		(net "M_D_CPU0_SA_CS_N<0>")
	)
	(segment
		(start 347.003116 -259.081016)
		(end 347.003116 -259.616702)
		(width 0.20066)
		(layer "F.Cu")
		(net "M_D_CPU0_SA_CS_N<0>")
	)
	(segment
		(start 347.003116 -259.616702)
		(end 347.002862 -259.616956)
		(width 0.20066)
		(layer "F.Cu")
		(net "M_D_CPU0_SA_CS_N<0>")
	)
	(segment
		(start 276.78634 -264.88898)
		(end 276.621494 -265.053826)
		(width 0.18288)
		(layer "In11.Cu")
		(net "M_D_CPU0_SA_CS_N<0>")
	)
	(segment
		(start 296.01795 -265.03757)
		(end 295.871646 -264.891266)
		(width 0.18288)
		(layer "In11.Cu")
		(net "M_D_CPU0_SA_CS_N<0>")
	)
	(segment
		(start 330.927202 -258.587748)
		(end 329.864212 -258.587748)
		(width 0.18288)
		(layer "In11.Cu")
		(net "M_D_CPU0_SA_CS_N<0>")
	)
	(segment
		(start 293.410894 -264.749026)
		(end 292.130734 -264.749026)
		(width 0.18288)
		(layer "In11.Cu")
		(net "M_D_CPU0_SA_CS_N<0>")
	)
	(segment
		(start 342.971374 -259.121402)
		(end 342.96096 -259.127498)
		(width 0.088646)
		(layer "In11.Cu")
		(net "M_D_CPU0_SA_CS_N<0>")
	)
	(segment
		(start 295.871646 -264.891266)
		(end 293.553134 -264.891266)
		(width 0.18288)
		(layer "In11.Cu")
		(net "M_D_CPU0_SA_CS_N<0>")
	)
	(segment
		(start 263.750552 -267.441934)
		(end 263.243568 -267.948918)
		(width 0.18288)
		(layer "In11.Cu")
		(net "M_D_CPU0_SA_CS_N<0>")
	)
	(segment
		(start 310.174894 -264.114026)
		(end 306.941728 -264.114026)
		(width 0.18288)
		(layer "In11.Cu")
		(net "M_D_CPU0_SA_CS_N<0>")
	)
	(segment
		(start 265.593068 -267.441934)
		(end 263.750552 -267.441934)
		(width 0.18288)
		(layer "In11.Cu")
		(net "M_D_CPU0_SA_CS_N<0>")
	)
	(segment
		(start 288.018982 -264.743692)
		(end 284.795214 -264.743692)
		(width 0.18288)
		(layer "In11.Cu")
		(net "M_D_CPU0_SA_CS_N<0>")
	)
	(segment
		(start 265.745722 -267.28928)
		(end 265.593068 -267.441934)
		(width 0.18288)
		(layer "In11.Cu")
		(net "M_D_CPU0_SA_CS_N<0>")
	)
	(segment
		(start 267.372846 -267.28928)
		(end 265.745722 -267.28928)
		(width 0.18288)
		(layer "In11.Cu")
		(net "M_D_CPU0_SA_CS_N<0>")
	)
	(segment
		(start 299.708824 -264.714736)
		(end 299.532294 -264.891266)
		(width 0.18288)
		(layer "In11.Cu")
		(net "M_D_CPU0_SA_CS_N<0>")
	)
	(segment
		(start 275.630894 -265.053826)
		(end 275.148294 -265.536426)
		(width 0.18288)
		(layer "In11.Cu")
		(net "M_D_CPU0_SA_CS_N<0>")
	)
	(segment
		(start 303.855374 -263.998456)
		(end 303.139094 -264.714736)
		(width 0.18288)
		(layer "In11.Cu")
		(net "M_D_CPU0_SA_CS_N<0>")
	)
	(segment
		(start 275.148294 -265.536426)
		(end 274.005294 -265.536426)
		(width 0.18288)
		(layer "In11.Cu")
		(net "M_D_CPU0_SA_CS_N<0>")
	)
	(segment
		(start 280.253948 -264.88898)
		(end 276.78634 -264.88898)
		(width 0.18288)
		(layer "In11.Cu")
		(net "M_D_CPU0_SA_CS_N<0>")
	)
	(segment
		(start 292.130734 -264.749026)
		(end 291.800534 -265.079226)
		(width 0.18288)
		(layer "In11.Cu")
		(net "M_D_CPU0_SA_CS_N<0>")
	)
	(segment
		(start 272.989294 -266.552426)
		(end 272.036794 -266.552426)
		(width 0.18288)
		(layer "In11.Cu")
		(net "M_D_CPU0_SA_CS_N<0>")
	)
	(segment
		(start 298.090082 -265.03757)
		(end 296.01795 -265.03757)
		(width 0.18288)
		(layer "In11.Cu")
		(net "M_D_CPU0_SA_CS_N<0>")
	)
	(segment
		(start 346.250514 -259.292598)
		(end 345.96451 -259.127498)
		(width 0.088646)
		(layer "In11.Cu")
		(net "M_D_CPU0_SA_CS_N<0>")
	)
	(segment
		(start 284.795214 -264.743692)
		(end 284.647894 -264.891012)
		(width 0.18288)
		(layer "In11.Cu")
		(net "M_D_CPU0_SA_CS_N<0>")
	)
	(segment
		(start 344.855546 -259.118862)
		(end 344.840814 -259.127498)
		(width 0.088646)
		(layer "In11.Cu")
		(net "M_D_CPU0_SA_CS_N<0>")
	)
	(segment
		(start 319.824862 -260.52653)
		(end 319.52819 -260.52653)
		(width 0.18288)
		(layer "In11.Cu")
		(net "M_D_CPU0_SA_CS_N<0>")
	)
	(segment
		(start 340.156546 -259.118862)
		(end 340.141814 -259.127498)
		(width 0.088646)
		(layer "In11.Cu")
		(net "M_D_CPU0_SA_CS_N<0>")
	)
	(segment
		(start 306.941728 -264.114026)
		(end 306.826158 -263.998456)
		(width 0.18288)
		(layer "In11.Cu")
		(net "M_D_CPU0_SA_CS_N<0>")
	)
	(segment
		(start 288.354516 -265.079226)
		(end 288.018982 -264.743692)
		(width 0.18288)
		(layer "In11.Cu")
		(net "M_D_CPU0_SA_CS_N<0>")
	)
	(segment
		(start 291.800534 -265.079226)
		(end 288.354516 -265.079226)
		(width 0.18288)
		(layer "In11.Cu")
		(net "M_D_CPU0_SA_CS_N<0>")
	)
	(segment
		(start 329.864212 -258.587748)
		(end 329.39101 -259.06095)
		(width 0.18288)
		(layer "In11.Cu")
		(net "M_D_CPU0_SA_CS_N<0>")
	)
	(segment
		(start 276.621494 -265.053826)
		(end 275.630894 -265.053826)
		(width 0.18288)
		(layer "In11.Cu")
		(net "M_D_CPU0_SA_CS_N<0>")
	)
	(segment
		(start 270.503142 -268.086078)
		(end 269.715488 -268.086078)
		(width 0.18288)
		(layer "In11.Cu")
		(net "M_D_CPU0_SA_CS_N<0>")
	)
	(segment
		(start 331.690218 -258.587748)
		(end 330.927202 -258.587748)
		(width 0.088646)
		(layer "In11.Cu")
		(net "M_D_CPU0_SA_CS_N<0>")
	)
	(segment
		(start 338.272374 -259.121402)
		(end 338.26196 -259.127498)
		(width 0.088646)
		(layer "In11.Cu")
		(net "M_D_CPU0_SA_CS_N<0>")
	)
	(segment
		(start 284.647894 -264.891012)
		(end 282.98521 -264.891012)
		(width 0.18288)
		(layer "In11.Cu")
		(net "M_D_CPU0_SA_CS_N<0>")
	)
	(segment
		(start 315.415422 -262.230108)
		(end 313.72429 -262.230108)
		(width 0.18288)
		(layer "In11.Cu")
		(net "M_D_CPU0_SA_CS_N<0>")
	)
	(segment
		(start 282.368752 -265.50747)
		(end 280.872438 -265.50747)
		(width 0.18288)
		(layer "In11.Cu")
		(net "M_D_CPU0_SA_CS_N<0>")
	)
	(segment
		(start 319.52819 -260.52653)
		(end 315.415422 -262.230108)
		(width 0.18288)
		(layer "In11.Cu")
		(net "M_D_CPU0_SA_CS_N<0>")
	)
	(segment
		(start 257.625342 -268.30655)
		(end 257.185414 -267.866622)
		(width 0.18288)
		(layer "In11.Cu")
		(net "M_D_CPU0_SA_CS_N<0>")
	)
	(segment
		(start 313.72429 -262.230108)
		(end 312.711084 -263.243314)
		(width 0.18288)
		(layer "In11.Cu")
		(net "M_D_CPU0_SA_CS_N<0>")
	)
	(segment
		(start 262.03402 -267.948918)
		(end 261.676388 -268.30655)
		(width 0.18288)
		(layer "In11.Cu")
		(net "M_D_CPU0_SA_CS_N<0>")
	)
	(segment
		(start 267.525246 -267.44168)
		(end 267.372846 -267.28928)
		(width 0.18288)
		(layer "In11.Cu")
		(net "M_D_CPU0_SA_CS_N<0>")
	)
	(segment
		(start 306.826158 -263.998456)
		(end 303.855374 -263.998456)
		(width 0.18288)
		(layer "In11.Cu")
		(net "M_D_CPU0_SA_CS_N<0>")
	)
	(segment
		(start 321.290442 -259.06095)
		(end 319.824862 -260.52653)
		(width 0.18288)
		(layer "In11.Cu")
		(net "M_D_CPU0_SA_CS_N<0>")
	)
	(segment
		(start 280.872438 -265.50747)
		(end 280.253948 -264.88898)
		(width 0.18288)
		(layer "In11.Cu")
		(net "M_D_CPU0_SA_CS_N<0>")
	)
	(segment
		(start 303.139094 -264.714736)
		(end 299.708824 -264.714736)
		(width 0.18288)
		(layer "In11.Cu")
		(net "M_D_CPU0_SA_CS_N<0>")
	)
	(segment
		(start 269.715488 -268.086078)
		(end 269.07109 -267.44168)
		(width 0.18288)
		(layer "In11.Cu")
		(net "M_D_CPU0_SA_CS_N<0>")
	)
	(segment
		(start 261.676388 -268.30655)
		(end 257.625342 -268.30655)
		(width 0.18288)
		(layer "In11.Cu")
		(net "M_D_CPU0_SA_CS_N<0>")
	)
	(segment
		(start 269.07109 -267.44168)
		(end 267.525246 -267.44168)
		(width 0.18288)
		(layer "In11.Cu")
		(net "M_D_CPU0_SA_CS_N<0>")
	)
	(segment
		(start 293.553134 -264.891266)
		(end 293.410894 -264.749026)
		(width 0.18288)
		(layer "In11.Cu")
		(net "M_D_CPU0_SA_CS_N<0>")
	)
	(segment
		(start 311.691782 -263.243314)
		(end 310.588152 -263.700768)
		(width 0.18288)
		(layer "In11.Cu")
		(net "M_D_CPU0_SA_CS_N<0>")
	)
	(segment
		(start 274.005294 -265.536426)
		(end 272.989294 -266.552426)
		(width 0.18288)
		(layer "In11.Cu")
		(net "M_D_CPU0_SA_CS_N<0>")
	)
	(segment
		(start 272.036794 -266.552426)
		(end 270.503142 -268.086078)
		(width 0.18288)
		(layer "In11.Cu")
		(net "M_D_CPU0_SA_CS_N<0>")
	)
	(segment
		(start 298.236386 -264.891266)
		(end 298.090082 -265.03757)
		(width 0.18288)
		(layer "In11.Cu")
		(net "M_D_CPU0_SA_CS_N<0>")
	)
	(segment
		(start 341.096346 -259.118862)
		(end 341.081614 -259.127498)
		(width 0.088646)
		(layer "In11.Cu")
		(net "M_D_CPU0_SA_CS_N<0>")
	)
	(segment
		(start 310.588152 -263.700768)
		(end 310.174894 -264.114026)
		(width 0.18288)
		(layer "In11.Cu")
		(net "M_D_CPU0_SA_CS_N<0>")
	)
	(segment
		(start 282.98521 -264.891012)
		(end 282.368752 -265.50747)
		(width 0.18288)
		(layer "In11.Cu")
		(net "M_D_CPU0_SA_CS_N<0>")
	)
	(segment
		(start 329.39101 -259.06095)
		(end 321.290442 -259.06095)
		(width 0.18288)
		(layer "In11.Cu")
		(net "M_D_CPU0_SA_CS_N<0>")
	)
	(segment
		(start 332.170786 -259.068316)
		(end 331.690218 -258.587748)
		(width 0.088646)
		(layer "In11.Cu")
		(net "M_D_CPU0_SA_CS_N<0>")
	)
	(segment
		(start 299.532294 -264.891266)
		(end 298.236386 -264.891266)
		(width 0.18288)
		(layer "In11.Cu")
		(net "M_D_CPU0_SA_CS_N<0>")
	)
	(segment
		(start 312.711084 -263.243314)
		(end 311.691782 -263.243314)
		(width 0.18288)
		(layer "In11.Cu")
		(net "M_D_CPU0_SA_CS_N<0>")
	)
	(segment
		(start 342.031828 -259.121402)
		(end 342.021414 -259.127498)
		(width 0.088646)
		(layer "In11.Cu")
		(net "M_D_CPU0_SA_CS_N<0>")
	)
	(segment
		(start 345.780614 -259.127498)
		(end 345.78036 -259.127498)
		(width 0.088646)
		(layer "In11.Cu")
		(net "M_D_CPU0_SA_CS_N<0>")
	)
	(segment
		(start 343.915746 -259.118862)
		(end 343.901014 -259.127498)
		(width 0.088646)
		(layer "In11.Cu")
		(net "M_D_CPU0_SA_CS_N<0>")
	)
	(segment
		(start 263.243568 -267.948918)
		(end 262.03402 -267.948918)
		(width 0.18288)
		(layer "In11.Cu")
		(net "M_D_CPU0_SA_CS_N<0>")
	)
	(arc
		(start 343.901014 -259.127498)
		(mid 343.713816 -259.177641)
		(end 343.526618 -259.127498)
		(width 0.088646)
		(layer "In11.Cu")
		(net "M_D_CPU0_SA_CS_N<0>")
	)
	(arc
		(start 338.827618 -259.127498)
		(mid 338.550805 -259.051628)
		(end 338.272374 -259.121402)
		(width 0.088646)
		(layer "In11.Cu")
		(net "M_D_CPU0_SA_CS_N<0>")
	)
	(arc
		(start 334.128364 -259.127498)
		(mid 333.845662 -259.051722)
		(end 333.56296 -259.127498)
		(width 0.088646)
		(layer "In11.Cu")
		(net "M_D_CPU0_SA_CS_N<0>")
	)
	(arc
		(start 347.002862 -259.616956)
		(mid 346.771042 -259.450624)
		(end 346.498164 -259.367274)
		(width 0.088646)
		(layer "In11.Cu")
		(net "M_D_CPU0_SA_CS_N<0>")
	)
	(arc
		(start 333.56296 -259.127498)
		(mid 333.375762 -259.177641)
		(end 333.188564 -259.127498)
		(width 0.088646)
		(layer "In11.Cu")
		(net "M_D_CPU0_SA_CS_N<0>")
	)
	(arc
		(start 339.767418 -259.127498)
		(mid 339.484716 -259.051722)
		(end 339.202014 -259.127498)
		(width 0.088646)
		(layer "In11.Cu")
		(net "M_D_CPU0_SA_CS_N<0>")
	)
	(arc
		(start 343.526618 -259.127498)
		(mid 343.249805 -259.051628)
		(end 342.971374 -259.121402)
		(width 0.088646)
		(layer "In11.Cu")
		(net "M_D_CPU0_SA_CS_N<0>")
	)
	(arc
		(start 345.78036 -259.127498)
		(mid 345.593306 -259.177582)
		(end 345.406218 -259.127498)
		(width 0.088646)
		(layer "In11.Cu")
		(net "M_D_CPU0_SA_CS_N<0>")
	)
	(arc
		(start 341.647018 -259.127498)
		(mid 341.372819 -259.051663)
		(end 341.096346 -259.118862)
		(width 0.088646)
		(layer "In11.Cu")
		(net "M_D_CPU0_SA_CS_N<0>")
	)
	(arc
		(start 332.248764 -259.127498)
		(mid 332.207834 -259.100465)
		(end 332.170786 -259.068316)
		(width 0.088646)
		(layer "In11.Cu")
		(net "M_D_CPU0_SA_CS_N<0>")
	)
	(arc
		(start 336.007964 -259.127498)
		(mid 335.725262 -259.051722)
		(end 335.44256 -259.127498)
		(width 0.088646)
		(layer "In11.Cu")
		(net "M_D_CPU0_SA_CS_N<0>")
	)
	(arc
		(start 342.021414 -259.127498)
		(mid 341.834216 -259.177641)
		(end 341.647018 -259.127498)
		(width 0.088646)
		(layer "In11.Cu")
		(net "M_D_CPU0_SA_CS_N<0>")
	)
	(arc
		(start 345.406218 -259.127498)
		(mid 345.132019 -259.051663)
		(end 344.855546 -259.118862)
		(width 0.088646)
		(layer "In11.Cu")
		(net "M_D_CPU0_SA_CS_N<0>")
	)
	(arc
		(start 345.96451 -259.127498)
		(mid 345.872562 -259.102861)
		(end 345.780614 -259.127498)
		(width 0.088646)
		(layer "In11.Cu")
		(net "M_D_CPU0_SA_CS_N<0>")
	)
	(arc
		(start 337.887564 -259.127498)
		(mid 337.604862 -259.051722)
		(end 337.32216 -259.127498)
		(width 0.088646)
		(layer "In11.Cu")
		(net "M_D_CPU0_SA_CS_N<0>")
	)
	(arc
		(start 332.62316 -259.127498)
		(mid 332.435962 -259.177641)
		(end 332.248764 -259.127498)
		(width 0.088646)
		(layer "In11.Cu")
		(net "M_D_CPU0_SA_CS_N<0>")
	)
	(arc
		(start 344.840814 -259.127498)
		(mid 344.653616 -259.177641)
		(end 344.466418 -259.127498)
		(width 0.088646)
		(layer "In11.Cu")
		(net "M_D_CPU0_SA_CS_N<0>")
	)
	(arc
		(start 338.26196 -259.127498)
		(mid 338.074762 -259.177641)
		(end 337.887564 -259.127498)
		(width 0.088646)
		(layer "In11.Cu")
		(net "M_D_CPU0_SA_CS_N<0>")
	)
	(arc
		(start 335.068164 -259.127498)
		(mid 334.785462 -259.051722)
		(end 334.50276 -259.127498)
		(width 0.088646)
		(layer "In11.Cu")
		(net "M_D_CPU0_SA_CS_N<0>")
	)
	(arc
		(start 337.32216 -259.127498)
		(mid 337.134962 -259.177641)
		(end 336.947764 -259.127498)
		(width 0.088646)
		(layer "In11.Cu")
		(net "M_D_CPU0_SA_CS_N<0>")
	)
	(arc
		(start 340.707218 -259.127498)
		(mid 340.433019 -259.051663)
		(end 340.156546 -259.118862)
		(width 0.088646)
		(layer "In11.Cu")
		(net "M_D_CPU0_SA_CS_N<0>")
	)
	(arc
		(start 336.38236 -259.127498)
		(mid 336.195162 -259.177641)
		(end 336.007964 -259.127498)
		(width 0.088646)
		(layer "In11.Cu")
		(net "M_D_CPU0_SA_CS_N<0>")
	)
	(arc
		(start 336.947764 -259.127498)
		(mid 336.665062 -259.051722)
		(end 336.38236 -259.127498)
		(width 0.088646)
		(layer "In11.Cu")
		(net "M_D_CPU0_SA_CS_N<0>")
	)
	(arc
		(start 344.466418 -259.127498)
		(mid 344.192219 -259.051663)
		(end 343.915746 -259.118862)
		(width 0.088646)
		(layer "In11.Cu")
		(net "M_D_CPU0_SA_CS_N<0>")
	)
	(arc
		(start 346.498164 -259.367274)
		(mid 346.370012 -259.344287)
		(end 346.250514 -259.292598)
		(width 0.088646)
		(layer "In11.Cu")
		(net "M_D_CPU0_SA_CS_N<0>")
	)
	(arc
		(start 335.44256 -259.127498)
		(mid 335.255362 -259.177641)
		(end 335.068164 -259.127498)
		(width 0.088646)
		(layer "In11.Cu")
		(net "M_D_CPU0_SA_CS_N<0>")
	)
	(arc
		(start 334.50276 -259.127498)
		(mid 334.315562 -259.177641)
		(end 334.128364 -259.127498)
		(width 0.088646)
		(layer "In11.Cu")
		(net "M_D_CPU0_SA_CS_N<0>")
	)
	(arc
		(start 342.586564 -259.127498)
		(mid 342.310005 -259.051755)
		(end 342.031828 -259.121402)
		(width 0.088646)
		(layer "In11.Cu")
		(net "M_D_CPU0_SA_CS_N<0>")
	)
	(arc
		(start 339.202014 -259.127498)
		(mid 339.014816 -259.177641)
		(end 338.827618 -259.127498)
		(width 0.088646)
		(layer "In11.Cu")
		(net "M_D_CPU0_SA_CS_N<0>")
	)
	(arc
		(start 341.081614 -259.127498)
		(mid 340.894416 -259.177641)
		(end 340.707218 -259.127498)
		(width 0.088646)
		(layer "In11.Cu")
		(net "M_D_CPU0_SA_CS_N<0>")
	)
	(arc
		(start 340.141814 -259.127498)
		(mid 339.954616 -259.177641)
		(end 339.767418 -259.127498)
		(width 0.088646)
		(layer "In11.Cu")
		(net "M_D_CPU0_SA_CS_N<0>")
	)
	(arc
		(start 342.96096 -259.127498)
		(mid 342.773762 -259.177641)
		(end 342.586564 -259.127498)
		(width 0.088646)
		(layer "In11.Cu")
		(net "M_D_CPU0_SA_CS_N<0>")
	)
	(arc
		(start 333.188564 -259.127498)
		(mid 332.905862 -259.051722)
		(end 332.62316 -259.127498)
		(width 0.088646)
		(layer "In11.Cu")
		(net "M_D_CPU0_SA_CS_N<0>")
	)
	(segment
		(start 262.514334 -270.841724)
		(end 262.50011 -270.855948)
		(width 0.101854)
		(layer "F.Cu")
		(net "M_D_CPU0_SA_CB<7>")
	)
	(segment
		(start 265.369548 -270.841724)
		(end 264.825226 -270.841724)
		(width 0.20066)
		(layer "F.Cu")
		(net "M_D_CPU0_SA_CB<7>")
	)
	(segment
		(start 265.518646 -270.540988)
		(end 265.518646 -270.692626)
		(width 0.20066)
		(layer "F.Cu")
		(net "M_D_CPU0_SA_CB<7>")
	)
	(segment
		(start 347.942916 -261.244588)
		(end 347.942662 -261.244842)
		(width 0.20066)
		(layer "F.Cu")
		(net "M_D_CPU0_SA_CB<7>")
	)
	(segment
		(start 264.825226 -270.841724)
		(end 262.752332 -270.841724)
		(width 0.1016)
		(layer "F.Cu")
		(net "M_D_CPU0_SA_CB<7>")
	)
	(segment
		(start 265.64717 -270.412464)
		(end 265.518646 -270.540988)
		(width 0.20066)
		(layer "F.Cu")
		(net "M_D_CPU0_SA_CB<7>")
	)
	(segment
		(start 266.700762 -270.6243)
		(end 266.25423 -270.6243)
		(width 0.20066)
		(layer "F.Cu")
		(net "M_D_CPU0_SA_CB<7>")
	)
	(segment
		(start 266.25423 -270.6243)
		(end 266.042394 -270.412464)
		(width 0.20066)
		(layer "F.Cu")
		(net "M_D_CPU0_SA_CB<7>")
	)
	(segment
		(start 268.829282 -270.416782)
		(end 267.724382 -270.416782)
		(width 0.20066)
		(layer "F.Cu")
		(net "M_D_CPU0_SA_CB<7>")
	)
	(segment
		(start 266.90828 -270.416782)
		(end 266.700762 -270.6243)
		(width 0.20066)
		(layer "F.Cu")
		(net "M_D_CPU0_SA_CB<7>")
	)
	(segment
		(start 262.50011 -270.855948)
		(end 262.146288 -270.855948)
		(width 0.20066)
		(layer "F.Cu")
		(net "M_D_CPU0_SA_CB<7>")
	)
	(segment
		(start 262.146288 -270.855948)
		(end 262.003794 -270.713454)
		(width 0.20066)
		(layer "F.Cu")
		(net "M_D_CPU0_SA_CB<7>")
	)
	(segment
		(start 262.003794 -270.542766)
		(end 261.87781 -270.416782)
		(width 0.20066)
		(layer "F.Cu")
		(net "M_D_CPU0_SA_CB<7>")
	)
	(segment
		(start 265.518646 -270.692626)
		(end 265.369548 -270.841724)
		(width 0.20066)
		(layer "F.Cu")
		(net "M_D_CPU0_SA_CB<7>")
	)
	(segment
		(start 262.003794 -270.713454)
		(end 262.003794 -270.542766)
		(width 0.20066)
		(layer "F.Cu")
		(net "M_D_CPU0_SA_CB<7>")
	)
	(segment
		(start 262.752332 -270.841724)
		(end 262.514334 -270.841724)
		(width 0.101854)
		(layer "F.Cu")
		(net "M_D_CPU0_SA_CB<7>")
	)
	(segment
		(start 261.87781 -270.416782)
		(end 260.180582 -270.416782)
		(width 0.20066)
		(layer "F.Cu")
		(net "M_D_CPU0_SA_CB<7>")
	)
	(segment
		(start 347.942916 -260.708902)
		(end 347.942916 -261.244588)
		(width 0.20066)
		(layer "F.Cu")
		(net "M_D_CPU0_SA_CB<7>")
	)
	(segment
		(start 267.724382 -270.416782)
		(end 266.90828 -270.416782)
		(width 0.20066)
		(layer "F.Cu")
		(net "M_D_CPU0_SA_CB<7>")
	)
	(segment
		(start 266.042394 -270.412464)
		(end 265.64717 -270.412464)
		(width 0.20066)
		(layer "F.Cu")
		(net "M_D_CPU0_SA_CB<7>")
	)
	(segment
		(start 295.449752 -268.330426)
		(end 295.226486 -268.330426)
		(width 0.18288)
		(layer "In11.Cu")
		(net "M_D_CPU0_SA_CB<7>")
	)
	(segment
		(start 336.392774 -260.749034)
		(end 336.38236 -260.75513)
		(width 0.088646)
		(layer "In11.Cu")
		(net "M_D_CPU0_SA_CB<7>")
	)
	(segment
		(start 290.37153 -267.685266)
		(end 290.171632 -267.885164)
		(width 0.18288)
		(layer "In11.Cu")
		(net "M_D_CPU0_SA_CB<7>")
	)
	(segment
		(start 308.635908 -267.146786)
		(end 308.635908 -267.426186)
		(width 0.18288)
		(layer "In11.Cu")
		(net "M_D_CPU0_SA_CB<7>")
	)
	(segment
		(start 331.632306 -260.679438)
		(end 331.599794 -260.71195)
		(width 0.088646)
		(layer "In11.Cu")
		(net "M_D_CPU0_SA_CB<7>")
	)
	(segment
		(start 269.30731 -270.89481)
		(end 268.829282 -270.416782)
		(width 0.18288)
		(layer "In11.Cu")
		(net "M_D_CPU0_SA_CB<7>")
	)
	(segment
		(start 270.907002 -270.89481)
		(end 269.30731 -270.89481)
		(width 0.18288)
		(layer "In11.Cu")
		(net "M_D_CPU0_SA_CB<7>")
	)
	(segment
		(start 295.642792 -267.979652)
		(end 295.642792 -268.137386)
		(width 0.18288)
		(layer "In11.Cu")
		(net "M_D_CPU0_SA_CB<7>")
	)
	(segment
		(start 297.887898 -268.330426)
		(end 296.536872 -268.330426)
		(width 0.18288)
		(layer "In11.Cu")
		(net "M_D_CPU0_SA_CB<7>")
	)
	(segment
		(start 305.547522 -267.942822)
		(end 305.232562 -267.942822)
		(width 0.18288)
		(layer "In11.Cu")
		(net "M_D_CPU0_SA_CB<7>")
	)
	(segment
		(start 286.29991 -268.011148)
		(end 286.116522 -267.82776)
		(width 0.18288)
		(layer "In11.Cu")
		(net "M_D_CPU0_SA_CB<7>")
	)
	(segment
		(start 274.713446 -269.067026)
		(end 273.48053 -269.067026)
		(width 0.18288)
		(layer "In11.Cu")
		(net "M_D_CPU0_SA_CB<7>")
	)
	(segment
		(start 308.828948 -266.953746)
		(end 308.635908 -267.146786)
		(width 0.18288)
		(layer "In11.Cu")
		(net "M_D_CPU0_SA_CB<7>")
	)
	(segment
		(start 309.143908 -266.953746)
		(end 308.828948 -266.953746)
		(width 0.18288)
		(layer "In11.Cu")
		(net "M_D_CPU0_SA_CB<7>")
	)
	(segment
		(start 319.170304 -263.661652)
		(end 314.218828 -265.712702)
		(width 0.18288)
		(layer "In11.Cu")
		(net "M_D_CPU0_SA_CB<7>")
	)
	(segment
		(start 295.226486 -268.330426)
		(end 295.188386 -268.292326)
		(width 0.18288)
		(layer "In11.Cu")
		(net "M_D_CPU0_SA_CB<7>")
	)
	(segment
		(start 337.332828 -260.749034)
		(end 337.322414 -260.75513)
		(width 0.088646)
		(layer "In11.Cu")
		(net "M_D_CPU0_SA_CB<7>")
	)
	(segment
		(start 286.67329 -268.011148)
		(end 286.29991 -268.011148)
		(width 0.18288)
		(layer "In11.Cu")
		(net "M_D_CPU0_SA_CB<7>")
	)
	(segment
		(start 290.71951 -267.685266)
		(end 290.37153 -267.685266)
		(width 0.18288)
		(layer "In11.Cu")
		(net "M_D_CPU0_SA_CB<7>")
	)
	(segment
		(start 272.346166 -269.455646)
		(end 270.907002 -270.89481)
		(width 0.18288)
		(layer "In11.Cu")
		(net "M_D_CPU0_SA_CB<7>")
	)
	(segment
		(start 347.942662 -261.244842)
		(end 347.665294 -260.979412)
		(width 0.088646)
		(layer "In11.Cu")
		(net "M_D_CPU0_SA_CB<7>")
	)
	(segment
		(start 275.099526 -269.703296)
		(end 274.906486 -269.510256)
		(width 0.18288)
		(layer "In11.Cu")
		(net "M_D_CPU0_SA_CB<7>")
	)
	(segment
		(start 282.653232 -268.478508)
		(end 280.286968 -268.478508)
		(width 0.18288)
		(layer "In11.Cu")
		(net "M_D_CPU0_SA_CB<7>")
	)
	(segment
		(start 293.680388 -267.57884)
		(end 293.502842 -267.756386)
		(width 0.18288)
		(layer "In11.Cu")
		(net "M_D_CPU0_SA_CB<7>")
	)
	(segment
		(start 292.845236 -268.101826)
		(end 292.191694 -268.101826)
		(width 0.18288)
		(layer "In11.Cu")
		(net "M_D_CPU0_SA_CB<7>")
	)
	(segment
		(start 305.232562 -267.942822)
		(end 305.039522 -267.749782)
		(width 0.18288)
		(layer "In11.Cu")
		(net "M_D_CPU0_SA_CB<7>")
	)
	(segment
		(start 331.966062 -260.679438)
		(end 331.632306 -260.679438)
		(width 0.088646)
		(layer "In11.Cu")
		(net "M_D_CPU0_SA_CB<7>")
	)
	(segment
		(start 313.39409 -265.712702)
		(end 312.376566 -266.730226)
		(width 0.18288)
		(layer "In11.Cu")
		(net "M_D_CPU0_SA_CB<7>")
	)
	(segment
		(start 296.150792 -267.786612)
		(end 295.835832 -267.786612)
		(width 0.18288)
		(layer "In11.Cu")
		(net "M_D_CPU0_SA_CB<7>")
	)
	(segment
		(start 341.096346 -260.746494)
		(end 341.081614 -260.75513)
		(width 0.088646)
		(layer "In11.Cu")
		(net "M_D_CPU0_SA_CB<7>")
	)
	(segment
		(start 286.99587 -267.44295)
		(end 286.83331 -267.60551)
		(width 0.18288)
		(layer "In11.Cu")
		(net "M_D_CPU0_SA_CB<7>")
	)
	(segment
		(start 286.116522 -267.82776)
		(end 286.116522 -267.621258)
		(width 0.18288)
		(layer "In11.Cu")
		(net "M_D_CPU0_SA_CB<7>")
	)
	(segment
		(start 275.800566 -269.067026)
		(end 275.607526 -269.260066)
		(width 0.18288)
		(layer "In11.Cu")
		(net "M_D_CPU0_SA_CB<7>")
	)
	(segment
		(start 305.740562 -267.431266)
		(end 305.740562 -267.749782)
		(width 0.18288)
		(layer "In11.Cu")
		(net "M_D_CPU0_SA_CB<7>")
	)
	(segment
		(start 294.22471 -267.77188)
		(end 294.03167 -267.57884)
		(width 0.18288)
		(layer "In11.Cu")
		(net "M_D_CPU0_SA_CB<7>")
	)
	(segment
		(start 275.414486 -269.703296)
		(end 275.099526 -269.703296)
		(width 0.18288)
		(layer "In11.Cu")
		(net "M_D_CPU0_SA_CB<7>")
	)
	(segment
		(start 299.633894 -267.644626)
		(end 299.43171 -267.442442)
		(width 0.18288)
		(layer "In11.Cu")
		(net "M_D_CPU0_SA_CB<7>")
	)
	(segment
		(start 286.83331 -267.60551)
		(end 286.83331 -267.851128)
		(width 0.18288)
		(layer "In11.Cu")
		(net "M_D_CPU0_SA_CB<7>")
	)
	(segment
		(start 308.635908 -267.426186)
		(end 308.442868 -267.619226)
		(width 0.18288)
		(layer "In11.Cu")
		(net "M_D_CPU0_SA_CB<7>")
	)
	(segment
		(start 309.336948 -267.426186)
		(end 309.336948 -267.146786)
		(width 0.18288)
		(layer "In11.Cu")
		(net "M_D_CPU0_SA_CB<7>")
	)
	(segment
		(start 284.35046 -267.57249)
		(end 284.220666 -267.442696)
		(width 0.18288)
		(layer "In11.Cu")
		(net "M_D_CPU0_SA_CB<7>")
	)
	(segment
		(start 347.665294 -260.979412)
		(end 347.285818 -260.75513)
		(width 0.088646)
		(layer "In11.Cu")
		(net "M_D_CPU0_SA_CB<7>")
	)
	(segment
		(start 274.906486 -269.260066)
		(end 274.713446 -269.067026)
		(width 0.18288)
		(layer "In11.Cu")
		(net "M_D_CPU0_SA_CB<7>")
	)
	(segment
		(start 285.460186 -267.442696)
		(end 285.330392 -267.57249)
		(width 0.18288)
		(layer "In11.Cu")
		(net "M_D_CPU0_SA_CB<7>")
	)
	(segment
		(start 275.607526 -269.260066)
		(end 275.607526 -269.510256)
		(width 0.18288)
		(layer "In11.Cu")
		(net "M_D_CPU0_SA_CB<7>")
	)
	(segment
		(start 290.171632 -267.885164)
		(end 290.171632 -268.170406)
		(width 0.18288)
		(layer "In11.Cu")
		(net "M_D_CPU0_SA_CB<7>")
	)
	(segment
		(start 284.220666 -267.442696)
		(end 283.689044 -267.442696)
		(width 0.18288)
		(layer "In11.Cu")
		(net "M_D_CPU0_SA_CB<7>")
	)
	(segment
		(start 285.330392 -267.57249)
		(end 284.35046 -267.57249)
		(width 0.18288)
		(layer "In11.Cu")
		(net "M_D_CPU0_SA_CB<7>")
	)
	(segment
		(start 290.87953 -267.845286)
		(end 290.71951 -267.685266)
		(width 0.18288)
		(layer "In11.Cu")
		(net "M_D_CPU0_SA_CB<7>")
	)
	(segment
		(start 275.607526 -269.510256)
		(end 275.414486 -269.703296)
		(width 0.18288)
		(layer "In11.Cu")
		(net "M_D_CPU0_SA_CB<7>")
	)
	(segment
		(start 283.689044 -267.442696)
		(end 282.653232 -268.478508)
		(width 0.18288)
		(layer "In11.Cu")
		(net "M_D_CPU0_SA_CB<7>")
	)
	(segment
		(start 345.791028 -260.749034)
		(end 345.780614 -260.75513)
		(width 0.088646)
		(layer "In11.Cu")
		(net "M_D_CPU0_SA_CB<7>")
	)
	(segment
		(start 286.83331 -267.851128)
		(end 286.67329 -268.011148)
		(width 0.18288)
		(layer "In11.Cu")
		(net "M_D_CPU0_SA_CB<7>")
	)
	(segment
		(start 290.87953 -268.170406)
		(end 290.87953 -267.845286)
		(width 0.18288)
		(layer "In11.Cu")
		(net "M_D_CPU0_SA_CB<7>")
	)
	(segment
		(start 307.050694 -267.238226)
		(end 305.933602 -267.238226)
		(width 0.18288)
		(layer "In11.Cu")
		(net "M_D_CPU0_SA_CB<7>")
	)
	(segment
		(start 296.343832 -268.137386)
		(end 296.343832 -267.979652)
		(width 0.18288)
		(layer "In11.Cu")
		(net "M_D_CPU0_SA_CB<7>")
	)
	(segment
		(start 290.171632 -268.170406)
		(end 290.011612 -268.330426)
		(width 0.18288)
		(layer "In11.Cu")
		(net "M_D_CPU0_SA_CB<7>")
	)
	(segment
		(start 293.035736 -268.292326)
		(end 292.845236 -268.101826)
		(width 0.18288)
		(layer "In11.Cu")
		(net "M_D_CPU0_SA_CB<7>")
	)
	(segment
		(start 293.342822 -268.292326)
		(end 293.035736 -268.292326)
		(width 0.18288)
		(layer "In11.Cu")
		(net "M_D_CPU0_SA_CB<7>")
	)
	(segment
		(start 278.513794 -268.292326)
		(end 278.297894 -268.076426)
		(width 0.18288)
		(layer "In11.Cu")
		(net "M_D_CPU0_SA_CB<7>")
	)
	(segment
		(start 287.827466 -268.068806)
		(end 287.827466 -267.63853)
		(width 0.18288)
		(layer "In11.Cu")
		(net "M_D_CPU0_SA_CB<7>")
	)
	(segment
		(start 276.977094 -268.076426)
		(end 275.986494 -269.067026)
		(width 0.18288)
		(layer "In11.Cu")
		(net "M_D_CPU0_SA_CB<7>")
	)
	(segment
		(start 302.88484 -268.203426)
		(end 301.462694 -268.203426)
		(width 0.18288)
		(layer "In11.Cu")
		(net "M_D_CPU0_SA_CB<7>")
	)
	(segment
		(start 296.343832 -267.979652)
		(end 296.150792 -267.786612)
		(width 0.18288)
		(layer "In11.Cu")
		(net "M_D_CPU0_SA_CB<7>")
	)
	(segment
		(start 287.631886 -267.44295)
		(end 286.99587 -267.44295)
		(width 0.18288)
		(layer "In11.Cu")
		(net "M_D_CPU0_SA_CB<7>")
	)
	(segment
		(start 291.03955 -268.330426)
		(end 290.87953 -268.170406)
		(width 0.18288)
		(layer "In11.Cu")
		(net "M_D_CPU0_SA_CB<7>")
	)
	(segment
		(start 330.953618 -260.71195)
		(end 322.120006 -260.71195)
		(width 0.18288)
		(layer "In11.Cu")
		(net "M_D_CPU0_SA_CB<7>")
	)
	(segment
		(start 294.03167 -267.57884)
		(end 293.680388 -267.57884)
		(width 0.18288)
		(layer "In11.Cu")
		(net "M_D_CPU0_SA_CB<7>")
	)
	(segment
		(start 310.37403 -267.619226)
		(end 309.529988 -267.619226)
		(width 0.18288)
		(layer "In11.Cu")
		(net "M_D_CPU0_SA_CB<7>")
	)
	(segment
		(start 295.642792 -268.137386)
		(end 295.449752 -268.330426)
		(width 0.18288)
		(layer "In11.Cu")
		(net "M_D_CPU0_SA_CB<7>")
	)
	(segment
		(start 322.120006 -260.71195)
		(end 319.170304 -263.661652)
		(width 0.18288)
		(layer "In11.Cu")
		(net "M_D_CPU0_SA_CB<7>")
	)
	(segment
		(start 338.272374 -260.749034)
		(end 338.26196 -260.75513)
		(width 0.088646)
		(layer "In11.Cu")
		(net "M_D_CPU0_SA_CB<7>")
	)
	(segment
		(start 293.502842 -268.132306)
		(end 293.342822 -268.292326)
		(width 0.18288)
		(layer "In11.Cu")
		(net "M_D_CPU0_SA_CB<7>")
	)
	(segment
		(start 273.09191 -269.455646)
		(end 272.346166 -269.455646)
		(width 0.18288)
		(layer "In11.Cu")
		(net "M_D_CPU0_SA_CB<7>")
	)
	(segment
		(start 285.93796 -267.442696)
		(end 285.460186 -267.442696)
		(width 0.18288)
		(layer "In11.Cu")
		(net "M_D_CPU0_SA_CB<7>")
	)
	(segment
		(start 280.100786 -268.292326)
		(end 278.513794 -268.292326)
		(width 0.18288)
		(layer "In11.Cu")
		(net "M_D_CPU0_SA_CB<7>")
	)
	(segment
		(start 295.188386 -268.292326)
		(end 294.38473 -268.292326)
		(width 0.18288)
		(layer "In11.Cu")
		(net "M_D_CPU0_SA_CB<7>")
	)
	(segment
		(start 303.85004 -267.238226)
		(end 302.88484 -268.203426)
		(width 0.18288)
		(layer "In11.Cu")
		(net "M_D_CPU0_SA_CB<7>")
	)
	(segment
		(start 292.191694 -268.101826)
		(end 291.963094 -268.330426)
		(width 0.18288)
		(layer "In11.Cu")
		(net "M_D_CPU0_SA_CB<7>")
	)
	(segment
		(start 295.835832 -267.786612)
		(end 295.642792 -267.979652)
		(width 0.18288)
		(layer "In11.Cu")
		(net "M_D_CPU0_SA_CB<7>")
	)
	(segment
		(start 300.903894 -267.644626)
		(end 299.633894 -267.644626)
		(width 0.18288)
		(layer "In11.Cu")
		(net "M_D_CPU0_SA_CB<7>")
	)
	(segment
		(start 305.039522 -267.749782)
		(end 305.039522 -267.431266)
		(width 0.18288)
		(layer "In11.Cu")
		(net "M_D_CPU0_SA_CB<7>")
	)
	(segment
		(start 308.442868 -267.619226)
		(end 307.431694 -267.619226)
		(width 0.18288)
		(layer "In11.Cu")
		(net "M_D_CPU0_SA_CB<7>")
	)
	(segment
		(start 291.963094 -268.330426)
		(end 291.03955 -268.330426)
		(width 0.18288)
		(layer "In11.Cu")
		(net "M_D_CPU0_SA_CB<7>")
	)
	(segment
		(start 305.039522 -267.431266)
		(end 304.846482 -267.238226)
		(width 0.18288)
		(layer "In11.Cu")
		(net "M_D_CPU0_SA_CB<7>")
	)
	(segment
		(start 280.286968 -268.478508)
		(end 280.100786 -268.292326)
		(width 0.18288)
		(layer "In11.Cu")
		(net "M_D_CPU0_SA_CB<7>")
	)
	(segment
		(start 339.212428 -260.749034)
		(end 339.202014 -260.75513)
		(width 0.088646)
		(layer "In11.Cu")
		(net "M_D_CPU0_SA_CB<7>")
	)
	(segment
		(start 278.297894 -268.076426)
		(end 276.977094 -268.076426)
		(width 0.18288)
		(layer "In11.Cu")
		(net "M_D_CPU0_SA_CB<7>")
	)
	(segment
		(start 293.502842 -267.756386)
		(end 293.502842 -268.132306)
		(width 0.18288)
		(layer "In11.Cu")
		(net "M_D_CPU0_SA_CB<7>")
	)
	(segment
		(start 273.48053 -269.067026)
		(end 273.09191 -269.455646)
		(width 0.18288)
		(layer "In11.Cu")
		(net "M_D_CPU0_SA_CB<7>")
	)
	(segment
		(start 307.431694 -267.619226)
		(end 307.050694 -267.238226)
		(width 0.18288)
		(layer "In11.Cu")
		(net "M_D_CPU0_SA_CB<7>")
	)
	(segment
		(start 314.218828 -265.712702)
		(end 313.39409 -265.712702)
		(width 0.18288)
		(layer "In11.Cu")
		(net "M_D_CPU0_SA_CB<7>")
	)
	(segment
		(start 309.336948 -267.146786)
		(end 309.143908 -266.953746)
		(width 0.18288)
		(layer "In11.Cu")
		(net "M_D_CPU0_SA_CB<7>")
	)
	(segment
		(start 304.846482 -267.238226)
		(end 303.85004 -267.238226)
		(width 0.18288)
		(layer "In11.Cu")
		(net "M_D_CPU0_SA_CB<7>")
	)
	(segment
		(start 275.986494 -269.067026)
		(end 275.800566 -269.067026)
		(width 0.18288)
		(layer "In11.Cu")
		(net "M_D_CPU0_SA_CB<7>")
	)
	(segment
		(start 290.011612 -268.330426)
		(end 288.089086 -268.330426)
		(width 0.18288)
		(layer "In11.Cu")
		(net "M_D_CPU0_SA_CB<7>")
	)
	(segment
		(start 274.906486 -269.510256)
		(end 274.906486 -269.260066)
		(width 0.18288)
		(layer "In11.Cu")
		(net "M_D_CPU0_SA_CB<7>")
	)
	(segment
		(start 346.730574 -260.749034)
		(end 346.72016 -260.75513)
		(width 0.088646)
		(layer "In11.Cu")
		(net "M_D_CPU0_SA_CB<7>")
	)
	(segment
		(start 288.089086 -268.330426)
		(end 287.827466 -268.068806)
		(width 0.18288)
		(layer "In11.Cu")
		(net "M_D_CPU0_SA_CB<7>")
	)
	(segment
		(start 294.22471 -268.132306)
		(end 294.22471 -267.77188)
		(width 0.18288)
		(layer "In11.Cu")
		(net "M_D_CPU0_SA_CB<7>")
	)
	(segment
		(start 331.599794 -260.71195)
		(end 330.953618 -260.71195)
		(width 0.088646)
		(layer "In11.Cu")
		(net "M_D_CPU0_SA_CB<7>")
	)
	(segment
		(start 305.740562 -267.749782)
		(end 305.547522 -267.942822)
		(width 0.18288)
		(layer "In11.Cu")
		(net "M_D_CPU0_SA_CB<7>")
	)
	(segment
		(start 301.462694 -268.203426)
		(end 300.903894 -267.644626)
		(width 0.18288)
		(layer "In11.Cu")
		(net "M_D_CPU0_SA_CB<7>")
	)
	(segment
		(start 305.933602 -267.238226)
		(end 305.740562 -267.431266)
		(width 0.18288)
		(layer "In11.Cu")
		(net "M_D_CPU0_SA_CB<7>")
	)
	(segment
		(start 287.827466 -267.63853)
		(end 287.631886 -267.44295)
		(width 0.18288)
		(layer "In11.Cu")
		(net "M_D_CPU0_SA_CB<7>")
	)
	(segment
		(start 286.116522 -267.621258)
		(end 285.93796 -267.442696)
		(width 0.18288)
		(layer "In11.Cu")
		(net "M_D_CPU0_SA_CB<7>")
	)
	(segment
		(start 311.26303 -266.730226)
		(end 310.37403 -267.619226)
		(width 0.18288)
		(layer "In11.Cu")
		(net "M_D_CPU0_SA_CB<7>")
	)
	(segment
		(start 294.38473 -268.292326)
		(end 294.22471 -268.132306)
		(width 0.18288)
		(layer "In11.Cu")
		(net "M_D_CPU0_SA_CB<7>")
	)
	(segment
		(start 296.536872 -268.330426)
		(end 296.343832 -268.137386)
		(width 0.18288)
		(layer "In11.Cu")
		(net "M_D_CPU0_SA_CB<7>")
	)
	(segment
		(start 309.529988 -267.619226)
		(end 309.336948 -267.426186)
		(width 0.18288)
		(layer "In11.Cu")
		(net "M_D_CPU0_SA_CB<7>")
	)
	(segment
		(start 312.376566 -266.730226)
		(end 311.26303 -266.730226)
		(width 0.18288)
		(layer "In11.Cu")
		(net "M_D_CPU0_SA_CB<7>")
	)
	(segment
		(start 298.775882 -267.442442)
		(end 297.887898 -268.330426)
		(width 0.18288)
		(layer "In11.Cu")
		(net "M_D_CPU0_SA_CB<7>")
	)
	(segment
		(start 299.43171 -267.442442)
		(end 298.775882 -267.442442)
		(width 0.18288)
		(layer "In11.Cu")
		(net "M_D_CPU0_SA_CB<7>")
	)
	(segment
		(start 340.151974 -260.749034)
		(end 340.14156 -260.75513)
		(width 0.088646)
		(layer "In11.Cu")
		(net "M_D_CPU0_SA_CB<7>")
	)
	(arc
		(start 341.647018 -260.75513)
		(mid 341.372789 -260.679205)
		(end 341.096346 -260.746494)
		(width 0.088646)
		(layer "In11.Cu")
		(net "M_D_CPU0_SA_CB<7>")
	)
	(arc
		(start 342.58631 -260.75513)
		(mid 342.303862 -260.679515)
		(end 342.021414 -260.75513)
		(width 0.088646)
		(layer "In11.Cu")
		(net "M_D_CPU0_SA_CB<7>")
	)
	(arc
		(start 336.948018 -260.75513)
		(mid 336.671205 -260.679294)
		(end 336.392774 -260.749034)
		(width 0.088646)
		(layer "In11.Cu")
		(net "M_D_CPU0_SA_CB<7>")
	)
	(arc
		(start 339.767164 -260.75513)
		(mid 339.490605 -260.679421)
		(end 339.212428 -260.749034)
		(width 0.088646)
		(layer "In11.Cu")
		(net "M_D_CPU0_SA_CB<7>")
	)
	(arc
		(start 340.14156 -260.75513)
		(mid 339.954362 -260.805273)
		(end 339.767164 -260.75513)
		(width 0.088646)
		(layer "In11.Cu")
		(net "M_D_CPU0_SA_CB<7>")
	)
	(arc
		(start 345.780614 -260.75513)
		(mid 345.593416 -260.805273)
		(end 345.406218 -260.75513)
		(width 0.088646)
		(layer "In11.Cu")
		(net "M_D_CPU0_SA_CB<7>")
	)
	(arc
		(start 346.345764 -260.75513)
		(mid 346.069205 -260.679421)
		(end 345.791028 -260.749034)
		(width 0.088646)
		(layer "In11.Cu")
		(net "M_D_CPU0_SA_CB<7>")
	)
	(arc
		(start 335.44256 -260.75513)
		(mid 335.255362 -260.805273)
		(end 335.068164 -260.75513)
		(width 0.088646)
		(layer "In11.Cu")
		(net "M_D_CPU0_SA_CB<7>")
	)
	(arc
		(start 338.827618 -260.75513)
		(mid 338.550805 -260.679294)
		(end 338.272374 -260.749034)
		(width 0.088646)
		(layer "In11.Cu")
		(net "M_D_CPU0_SA_CB<7>")
	)
	(arc
		(start 336.007964 -260.75513)
		(mid 335.725262 -260.679388)
		(end 335.44256 -260.75513)
		(width 0.088646)
		(layer "In11.Cu")
		(net "M_D_CPU0_SA_CB<7>")
	)
	(arc
		(start 340.707218 -260.75513)
		(mid 340.430405 -260.679294)
		(end 340.151974 -260.749034)
		(width 0.088646)
		(layer "In11.Cu")
		(net "M_D_CPU0_SA_CB<7>")
	)
	(arc
		(start 334.128364 -260.75513)
		(mid 333.845662 -260.679388)
		(end 333.56296 -260.75513)
		(width 0.088646)
		(layer "In11.Cu")
		(net "M_D_CPU0_SA_CB<7>")
	)
	(arc
		(start 347.285818 -260.75513)
		(mid 347.009005 -260.679294)
		(end 346.730574 -260.749034)
		(width 0.088646)
		(layer "In11.Cu")
		(net "M_D_CPU0_SA_CB<7>")
	)
	(arc
		(start 342.960706 -260.75513)
		(mid 342.773508 -260.805273)
		(end 342.58631 -260.75513)
		(width 0.088646)
		(layer "In11.Cu")
		(net "M_D_CPU0_SA_CB<7>")
	)
	(arc
		(start 332.248764 -260.75513)
		(mid 332.112398 -260.698652)
		(end 331.966062 -260.679438)
		(width 0.088646)
		(layer "In11.Cu")
		(net "M_D_CPU0_SA_CB<7>")
	)
	(arc
		(start 342.021414 -260.75513)
		(mid 341.834216 -260.805273)
		(end 341.647018 -260.75513)
		(width 0.088646)
		(layer "In11.Cu")
		(net "M_D_CPU0_SA_CB<7>")
	)
	(arc
		(start 332.62316 -260.75513)
		(mid 332.435962 -260.805273)
		(end 332.248764 -260.75513)
		(width 0.088646)
		(layer "In11.Cu")
		(net "M_D_CPU0_SA_CB<7>")
	)
	(arc
		(start 338.26196 -260.75513)
		(mid 338.074762 -260.805273)
		(end 337.887564 -260.75513)
		(width 0.088646)
		(layer "In11.Cu")
		(net "M_D_CPU0_SA_CB<7>")
	)
	(arc
		(start 346.72016 -260.75513)
		(mid 346.532962 -260.805273)
		(end 346.345764 -260.75513)
		(width 0.088646)
		(layer "In11.Cu")
		(net "M_D_CPU0_SA_CB<7>")
	)
	(arc
		(start 333.188564 -260.75513)
		(mid 332.905862 -260.679388)
		(end 332.62316 -260.75513)
		(width 0.088646)
		(layer "In11.Cu")
		(net "M_D_CPU0_SA_CB<7>")
	)
	(arc
		(start 339.202014 -260.75513)
		(mid 339.014816 -260.805273)
		(end 338.827618 -260.75513)
		(width 0.088646)
		(layer "In11.Cu")
		(net "M_D_CPU0_SA_CB<7>")
	)
	(arc
		(start 345.406218 -260.75513)
		(mid 345.123262 -260.679261)
		(end 344.840306 -260.75513)
		(width 0.088646)
		(layer "In11.Cu")
		(net "M_D_CPU0_SA_CB<7>")
	)
	(arc
		(start 343.526618 -260.75513)
		(mid 343.243662 -260.679261)
		(end 342.960706 -260.75513)
		(width 0.088646)
		(layer "In11.Cu")
		(net "M_D_CPU0_SA_CB<7>")
	)
	(arc
		(start 341.081614 -260.75513)
		(mid 340.894416 -260.805273)
		(end 340.707218 -260.75513)
		(width 0.088646)
		(layer "In11.Cu")
		(net "M_D_CPU0_SA_CB<7>")
	)
	(arc
		(start 343.901014 -260.75513)
		(mid 343.713816 -260.805273)
		(end 343.526618 -260.75513)
		(width 0.088646)
		(layer "In11.Cu")
		(net "M_D_CPU0_SA_CB<7>")
	)
	(arc
		(start 344.840306 -260.75513)
		(mid 344.653108 -260.805273)
		(end 344.46591 -260.75513)
		(width 0.088646)
		(layer "In11.Cu")
		(net "M_D_CPU0_SA_CB<7>")
	)
	(arc
		(start 337.887564 -260.75513)
		(mid 337.611005 -260.679421)
		(end 337.332828 -260.749034)
		(width 0.088646)
		(layer "In11.Cu")
		(net "M_D_CPU0_SA_CB<7>")
	)
	(arc
		(start 344.46591 -260.75513)
		(mid 344.183462 -260.679515)
		(end 343.901014 -260.75513)
		(width 0.088646)
		(layer "In11.Cu")
		(net "M_D_CPU0_SA_CB<7>")
	)
	(arc
		(start 337.322414 -260.75513)
		(mid 337.135216 -260.805273)
		(end 336.948018 -260.75513)
		(width 0.088646)
		(layer "In11.Cu")
		(net "M_D_CPU0_SA_CB<7>")
	)
	(arc
		(start 333.56296 -260.75513)
		(mid 333.375762 -260.805273)
		(end 333.188564 -260.75513)
		(width 0.088646)
		(layer "In11.Cu")
		(net "M_D_CPU0_SA_CB<7>")
	)
	(arc
		(start 336.38236 -260.75513)
		(mid 336.195162 -260.805273)
		(end 336.007964 -260.75513)
		(width 0.088646)
		(layer "In11.Cu")
		(net "M_D_CPU0_SA_CB<7>")
	)
	(arc
		(start 335.068164 -260.75513)
		(mid 334.785462 -260.679388)
		(end 334.50276 -260.75513)
		(width 0.088646)
		(layer "In11.Cu")
		(net "M_D_CPU0_SA_CB<7>")
	)
	(arc
		(start 334.50276 -260.75513)
		(mid 334.315562 -260.805273)
		(end 334.128364 -260.75513)
		(width 0.088646)
		(layer "In11.Cu")
		(net "M_D_CPU0_SA_CB<7>")
	)
	(segment
		(start 265.601958 -271.835626)
		(end 265.458194 -271.691862)
		(width 0.20066)
		(layer "F.Cu")
		(net "M_D_CPU0_SA_CB<6>")
	)
	(segment
		(start 265.458194 -271.691862)
		(end 264.825226 -271.691862)
		(width 0.20066)
		(layer "F.Cu")
		(net "M_D_CPU0_SA_CB<6>")
	)
	(segment
		(start 348.412562 -262.058404)
		(end 348.412816 -262.058658)
		(width 0.20066)
		(layer "F.Cu")
		(net "M_D_CPU0_SA_CB<6>")
	)
	(segment
		(start 265.601958 -272.161254)
		(end 265.601958 -271.835626)
		(width 0.20066)
		(layer "F.Cu")
		(net "M_D_CPU0_SA_CB<6>")
	)
	(segment
		(start 262.765286 -271.691862)
		(end 262.51027 -271.691862)
		(width 0.101854)
		(layer "F.Cu")
		(net "M_D_CPU0_SA_CB<6>")
	)
	(segment
		(start 268.829282 -272.116804)
		(end 267.724382 -272.116804)
		(width 0.20066)
		(layer "F.Cu")
		(net "M_D_CPU0_SA_CB<6>")
	)
	(segment
		(start 262.50011 -271.681702)
		(end 261.762748 -271.681702)
		(width 0.20066)
		(layer "F.Cu")
		(net "M_D_CPU0_SA_CB<6>")
	)
	(segment
		(start 261.327646 -272.116804)
		(end 260.180582 -272.116804)
		(width 0.20066)
		(layer "F.Cu")
		(net "M_D_CPU0_SA_CB<6>")
	)
	(segment
		(start 348.412562 -261.522718)
		(end 348.412562 -262.058404)
		(width 0.20066)
		(layer "F.Cu")
		(net "M_D_CPU0_SA_CB<6>")
	)
	(segment
		(start 264.825226 -271.691862)
		(end 262.765286 -271.691862)
		(width 0.1016)
		(layer "F.Cu")
		(net "M_D_CPU0_SA_CB<6>")
	)
	(segment
		(start 266.409678 -272.116804)
		(end 266.197842 -272.32864)
		(width 0.20066)
		(layer "F.Cu")
		(net "M_D_CPU0_SA_CB<6>")
	)
	(segment
		(start 261.762748 -271.681702)
		(end 261.327646 -272.116804)
		(width 0.20066)
		(layer "F.Cu")
		(net "M_D_CPU0_SA_CB<6>")
	)
	(segment
		(start 262.51027 -271.691862)
		(end 262.50011 -271.681702)
		(width 0.101854)
		(layer "F.Cu")
		(net "M_D_CPU0_SA_CB<6>")
	)
	(segment
		(start 267.724382 -272.116804)
		(end 266.409678 -272.116804)
		(width 0.20066)
		(layer "F.Cu")
		(net "M_D_CPU0_SA_CB<6>")
	)
	(segment
		(start 265.769344 -272.32864)
		(end 265.601958 -272.161254)
		(width 0.20066)
		(layer "F.Cu")
		(net "M_D_CPU0_SA_CB<6>")
	)
	(segment
		(start 266.197842 -272.32864)
		(end 265.769344 -272.32864)
		(width 0.20066)
		(layer "F.Cu")
		(net "M_D_CPU0_SA_CB<6>")
	)
	(segment
		(start 284.546294 -269.142464)
		(end 283.69768 -269.142464)
		(width 0.18288)
		(layer "In11.Cu")
		(net "M_D_CPU0_SA_CB<6>")
	)
	(segment
		(start 313.134502 -268.452854)
		(end 312.861706 -268.452854)
		(width 0.18288)
		(layer "In11.Cu")
		(net "M_D_CPU0_SA_CB<6>")
	)
	(segment
		(start 312.199782 -268.602206)
		(end 311.089802 -268.602206)
		(width 0.18288)
		(layer "In11.Cu")
		(net "M_D_CPU0_SA_CB<6>")
	)
	(segment
		(start 318.506348 -265.76274)
		(end 318.053466 -265.949938)
		(width 0.18288)
		(layer "In11.Cu")
		(net "M_D_CPU0_SA_CB<6>")
	)
	(segment
		(start 331.248512 -261.619746)
		(end 331.140308 -261.72795)
		(width 0.088646)
		(layer "In11.Cu")
		(net "M_D_CPU0_SA_CB<6>")
	)
	(segment
		(start 317.801498 -265.84529)
		(end 317.714376 -265.635486)
		(width 0.18288)
		(layer "In11.Cu")
		(net "M_D_CPU0_SA_CB<6>")
	)
	(segment
		(start 337.428586 -261.575296)
		(end 337.417664 -261.568946)
		(width 0.088646)
		(layer "In11.Cu")
		(net "M_D_CPU0_SA_CB<6>")
	)
	(segment
		(start 317.283592 -266.93241)
		(end 316.992254 -267.053314)
		(width 0.18288)
		(layer "In11.Cu")
		(net "M_D_CPU0_SA_CB<6>")
	)
	(segment
		(start 312.469022 -268.332966)
		(end 312.199782 -268.602206)
		(width 0.18288)
		(layer "In11.Cu")
		(net "M_D_CPU0_SA_CB<6>")
	)
	(segment
		(start 343.056464 -261.5692)
		(end 343.041732 -261.560564)
		(width 0.088646)
		(layer "In11.Cu")
		(net "M_D_CPU0_SA_CB<6>")
	)
	(segment
		(start 286.310578 -269.76451)
		(end 285.892494 -269.346426)
		(width 0.18288)
		(layer "In11.Cu")
		(net "M_D_CPU0_SA_CB<6>")
	)
	(segment
		(start 291.912294 -270.083026)
		(end 290.967922 -270.083026)
		(width 0.18288)
		(layer "In11.Cu")
		(net "M_D_CPU0_SA_CB<6>")
	)
	(segment
		(start 284.750256 -269.346426)
		(end 284.546294 -269.142464)
		(width 0.18288)
		(layer "In11.Cu")
		(net "M_D_CPU0_SA_CB<6>")
	)
	(segment
		(start 344.936064 -261.5692)
		(end 344.921332 -261.560564)
		(width 0.088646)
		(layer "In11.Cu")
		(net "M_D_CPU0_SA_CB<6>")
	)
	(segment
		(start 303.932336 -269.035784)
		(end 303.164494 -269.803626)
		(width 0.18288)
		(layer "In11.Cu")
		(net "M_D_CPU0_SA_CB<6>")
	)
	(segment
		(start 343.996264 -261.5692)
		(end 343.981532 -261.560564)
		(width 0.088646)
		(layer "In11.Cu")
		(net "M_D_CPU0_SA_CB<6>")
	)
	(segment
		(start 271.712182 -271.599914)
		(end 270.607282 -272.704814)
		(width 0.18288)
		(layer "In11.Cu")
		(net "M_D_CPU0_SA_CB<6>")
	)
	(segment
		(start 290.266882 -269.35684)
		(end 290.073842 -269.54988)
		(width 0.18288)
		(layer "In11.Cu")
		(net "M_D_CPU0_SA_CB<6>")
	)
	(segment
		(start 316.418976 -266.172442)
		(end 316.167262 -266.067794)
		(width 0.18288)
		(layer "In11.Cu")
		(net "M_D_CPU0_SA_CB<6>")
	)
	(segment
		(start 289.880802 -270.083026)
		(end 289.044634 -270.083026)
		(width 0.18288)
		(layer "In11.Cu")
		(net "M_D_CPU0_SA_CB<6>")
	)
	(segment
		(start 331.140308 -261.72795)
		(end 330.953618 -261.72795)
		(width 0.088646)
		(layer "In11.Cu")
		(net "M_D_CPU0_SA_CB<6>")
	)
	(segment
		(start 342.116664 -261.5692)
		(end 342.101932 -261.560564)
		(width 0.088646)
		(layer "In11.Cu")
		(net "M_D_CPU0_SA_CB<6>")
	)
	(segment
		(start 347.365574 -261.624826)
		(end 345.97213 -261.624826)
		(width 0.088646)
		(layer "In11.Cu")
		(net "M_D_CPU0_SA_CB<6>")
	)
	(segment
		(start 312.861706 -268.452854)
		(end 312.741818 -268.332966)
		(width 0.18288)
		(layer "In11.Cu")
		(net "M_D_CPU0_SA_CB<6>")
	)
	(segment
		(start 294.555164 -269.992348)
		(end 294.252904 -270.294608)
		(width 0.18288)
		(layer "In11.Cu")
		(net "M_D_CPU0_SA_CB<6>")
	)
	(segment
		(start 299.550328 -269.18666)
		(end 299.379894 -269.016226)
		(width 0.18288)
		(layer "In11.Cu")
		(net "M_D_CPU0_SA_CB<6>")
	)
	(segment
		(start 270.607282 -272.704814)
		(end 269.417292 -272.704814)
		(width 0.18288)
		(layer "In11.Cu")
		(net "M_D_CPU0_SA_CB<6>")
	)
	(segment
		(start 292.140894 -269.854426)
		(end 291.912294 -270.083026)
		(width 0.18288)
		(layer "In11.Cu")
		(net "M_D_CPU0_SA_CB<6>")
	)
	(segment
		(start 317.171324 -265.651742)
		(end 317.066676 -265.903964)
		(width 0.18288)
		(layer "In11.Cu")
		(net "M_D_CPU0_SA_CB<6>")
	)
	(segment
		(start 315.10605 -267.17117)
		(end 314.496196 -267.4239)
		(width 0.18288)
		(layer "In11.Cu")
		(net "M_D_CPU0_SA_CB<6>")
	)
	(segment
		(start 285.892494 -269.346426)
		(end 284.750256 -269.346426)
		(width 0.18288)
		(layer "In11.Cu")
		(net "M_D_CPU0_SA_CB<6>")
	)
	(segment
		(start 330.953618 -261.72795)
		(end 322.541138 -261.72795)
		(width 0.18288)
		(layer "In11.Cu")
		(net "M_D_CPU0_SA_CB<6>")
	)
	(segment
		(start 296.128694 -269.85214)
		(end 295.801034 -269.85214)
		(width 0.18288)
		(layer "In11.Cu")
		(net "M_D_CPU0_SA_CB<6>")
	)
	(segment
		(start 315.358018 -267.275818)
		(end 315.10605 -267.17117)
		(width 0.18288)
		(layer "In11.Cu")
		(net "M_D_CPU0_SA_CB<6>")
	)
	(segment
		(start 269.417292 -272.704814)
		(end 268.829282 -272.116804)
		(width 0.18288)
		(layer "In11.Cu")
		(net "M_D_CPU0_SA_CB<6>")
	)
	(segment
		(start 316.077854 -267.68552)
		(end 315.825632 -267.790168)
		(width 0.18288)
		(layer "In11.Cu")
		(net "M_D_CPU0_SA_CB<6>")
	)
	(segment
		(start 308.660546 -269.209774)
		(end 307.193442 -269.209774)
		(width 0.18288)
		(layer "In11.Cu")
		(net "M_D_CPU0_SA_CB<6>")
	)
	(segment
		(start 289.044634 -270.083026)
		(end 288.726118 -269.76451)
		(width 0.18288)
		(layer "In11.Cu")
		(net "M_D_CPU0_SA_CB<6>")
	)
	(segment
		(start 279.410414 -269.804134)
		(end 277.574502 -269.804134)
		(width 0.18288)
		(layer "In11.Cu")
		(net "M_D_CPU0_SA_CB<6>")
	)
	(segment
		(start 303.164494 -269.803626)
		(end 301.488094 -269.803626)
		(width 0.18288)
		(layer "In11.Cu")
		(net "M_D_CPU0_SA_CB<6>")
	)
	(segment
		(start 345.97213 -261.624826)
		(end 345.875864 -261.5692)
		(width 0.088646)
		(layer "In11.Cu")
		(net "M_D_CPU0_SA_CB<6>")
	)
	(segment
		(start 313.237626 -267.837158)
		(end 313.357514 -267.957046)
		(width 0.18288)
		(layer "In11.Cu")
		(net "M_D_CPU0_SA_CB<6>")
	)
	(segment
		(start 295.801034 -269.85214)
		(end 295.660826 -269.992348)
		(width 0.18288)
		(layer "In11.Cu")
		(net "M_D_CPU0_SA_CB<6>")
	)
	(segment
		(start 313.378088 -267.4239)
		(end 313.237626 -267.564362)
		(width 0.18288)
		(layer "In11.Cu")
		(net "M_D_CPU0_SA_CB<6>")
	)
	(segment
		(start 290.774882 -269.54988)
		(end 290.581842 -269.35684)
		(width 0.18288)
		(layer "In11.Cu")
		(net "M_D_CPU0_SA_CB<6>")
	)
	(segment
		(start 301.488094 -269.803626)
		(end 300.871128 -269.18666)
		(width 0.18288)
		(layer "In11.Cu")
		(net "M_D_CPU0_SA_CB<6>")
	)
	(segment
		(start 311.089802 -268.602206)
		(end 310.550306 -269.141702)
		(width 0.18288)
		(layer "In11.Cu")
		(net "M_D_CPU0_SA_CB<6>")
	)
	(segment
		(start 315.825632 -267.790168)
		(end 315.518546 -267.66266)
		(width 0.18288)
		(layer "In11.Cu")
		(net "M_D_CPU0_SA_CB<6>")
	)
	(segment
		(start 293.325296 -269.854426)
		(end 292.140894 -269.854426)
		(width 0.18288)
		(layer "In11.Cu")
		(net "M_D_CPU0_SA_CB<6>")
	)
	(segment
		(start 317.38824 -266.680188)
		(end 317.283592 -266.93241)
		(width 0.18288)
		(layer "In11.Cu")
		(net "M_D_CPU0_SA_CB<6>")
	)
	(segment
		(start 316.992254 -267.053314)
		(end 316.74054 -266.948666)
		(width 0.18288)
		(layer "In11.Cu")
		(net "M_D_CPU0_SA_CB<6>")
	)
	(segment
		(start 296.345864 -270.06931)
		(end 296.128694 -269.85214)
		(width 0.18288)
		(layer "In11.Cu")
		(net "M_D_CPU0_SA_CB<6>")
	)
	(segment
		(start 331.966062 -261.619746)
		(end 331.248512 -261.619746)
		(width 0.088646)
		(layer "In11.Cu")
		(net "M_D_CPU0_SA_CB<6>")
	)
	(segment
		(start 308.728618 -269.141702)
		(end 308.660546 -269.209774)
		(width 0.18288)
		(layer "In11.Cu")
		(net "M_D_CPU0_SA_CB<6>")
	)
	(segment
		(start 315.875924 -266.188698)
		(end 315.771276 -266.44092)
		(width 0.18288)
		(layer "In11.Cu")
		(net "M_D_CPU0_SA_CB<6>")
	)
	(segment
		(start 279.60066 -269.99438)
		(end 279.410414 -269.804134)
		(width 0.18288)
		(layer "In11.Cu")
		(net "M_D_CPU0_SA_CB<6>")
	)
	(segment
		(start 337.417664 -261.568946)
		(end 337.402932 -261.56031)
		(width 0.088646)
		(layer "In11.Cu")
		(net "M_D_CPU0_SA_CB<6>")
	)
	(segment
		(start 295.660826 -269.992348)
		(end 294.555164 -269.992348)
		(width 0.18288)
		(layer "In11.Cu")
		(net "M_D_CPU0_SA_CB<6>")
	)
	(segment
		(start 317.462662 -265.530838)
		(end 317.171324 -265.651742)
		(width 0.18288)
		(layer "In11.Cu")
		(net "M_D_CPU0_SA_CB<6>")
	)
	(segment
		(start 294.252904 -270.294608)
		(end 293.861744 -270.294608)
		(width 0.18288)
		(layer "In11.Cu")
		(net "M_D_CPU0_SA_CB<6>")
	)
	(segment
		(start 282.845764 -269.99438)
		(end 279.60066 -269.99438)
		(width 0.18288)
		(layer "In11.Cu")
		(net "M_D_CPU0_SA_CB<6>")
	)
	(segment
		(start 336.85226 -261.568946)
		(end 336.85226 -261.5692)
		(width 0.088646)
		(layer "In11.Cu")
		(net "M_D_CPU0_SA_CB<6>")
	)
	(segment
		(start 290.774882 -269.889986)
		(end 290.774882 -269.54988)
		(width 0.18288)
		(layer "In11.Cu")
		(net "M_D_CPU0_SA_CB<6>")
	)
	(segment
		(start 290.967922 -270.083026)
		(end 290.774882 -269.889986)
		(width 0.18288)
		(layer "In11.Cu")
		(net "M_D_CPU0_SA_CB<6>")
	)
	(segment
		(start 297.764454 -270.06931)
		(end 296.345864 -270.06931)
		(width 0.18288)
		(layer "In11.Cu")
		(net "M_D_CPU0_SA_CB<6>")
	)
	(segment
		(start 313.357514 -268.229842)
		(end 313.134502 -268.452854)
		(width 0.18288)
		(layer "In11.Cu")
		(net "M_D_CPU0_SA_CB<6>")
	)
	(segment
		(start 316.182248 -267.433044)
		(end 316.077854 -267.68552)
		(width 0.18288)
		(layer "In11.Cu")
		(net "M_D_CPU0_SA_CB<6>")
	)
	(segment
		(start 273.597116 -270.770604)
		(end 272.767806 -271.599914)
		(width 0.18288)
		(layer "In11.Cu")
		(net "M_D_CPU0_SA_CB<6>")
	)
	(segment
		(start 288.726118 -269.76451)
		(end 286.310578 -269.76451)
		(width 0.18288)
		(layer "In11.Cu")
		(net "M_D_CPU0_SA_CB<6>")
	)
	(segment
		(start 300.871128 -269.18666)
		(end 299.550328 -269.18666)
		(width 0.18288)
		(layer "In11.Cu")
		(net "M_D_CPU0_SA_CB<6>")
	)
	(segment
		(start 290.073842 -269.54988)
		(end 290.073842 -269.889986)
		(width 0.18288)
		(layer "In11.Cu")
		(net "M_D_CPU0_SA_CB<6>")
	)
	(segment
		(start 316.74054 -266.948666)
		(end 316.418976 -266.172442)
		(width 0.18288)
		(layer "In11.Cu")
		(net "M_D_CPU0_SA_CB<6>")
	)
	(segment
		(start 293.861744 -270.294608)
		(end 293.559484 -269.992348)
		(width 0.18288)
		(layer "In11.Cu")
		(net "M_D_CPU0_SA_CB<6>")
	)
	(segment
		(start 341.176864 -261.5692)
		(end 341.162132 -261.560564)
		(width 0.088646)
		(layer "In11.Cu")
		(net "M_D_CPU0_SA_CB<6>")
	)
	(segment
		(start 277.574502 -269.804134)
		(end 276.608032 -270.770604)
		(width 0.18288)
		(layer "In11.Cu")
		(net "M_D_CPU0_SA_CB<6>")
	)
	(segment
		(start 298.817538 -269.016226)
		(end 297.764454 -270.06931)
		(width 0.18288)
		(layer "In11.Cu")
		(net "M_D_CPU0_SA_CB<6>")
	)
	(segment
		(start 318.053466 -265.949938)
		(end 317.801498 -265.84529)
		(width 0.18288)
		(layer "In11.Cu")
		(net "M_D_CPU0_SA_CB<6>")
	)
	(segment
		(start 307.193442 -269.209774)
		(end 307.019452 -269.035784)
		(width 0.18288)
		(layer "In11.Cu")
		(net "M_D_CPU0_SA_CB<6>")
	)
	(segment
		(start 290.581842 -269.35684)
		(end 290.266882 -269.35684)
		(width 0.18288)
		(layer "In11.Cu")
		(net "M_D_CPU0_SA_CB<6>")
	)
	(segment
		(start 290.073842 -269.889986)
		(end 289.880802 -270.083026)
		(width 0.18288)
		(layer "In11.Cu")
		(net "M_D_CPU0_SA_CB<6>")
	)
	(segment
		(start 322.541138 -261.72795)
		(end 318.506348 -265.76274)
		(width 0.18288)
		(layer "In11.Cu")
		(net "M_D_CPU0_SA_CB<6>")
	)
	(segment
		(start 317.714376 -265.635486)
		(end 317.462662 -265.530838)
		(width 0.18288)
		(layer "In11.Cu")
		(net "M_D_CPU0_SA_CB<6>")
	)
	(segment
		(start 315.771276 -266.44092)
		(end 316.182248 -267.433044)
		(width 0.18288)
		(layer "In11.Cu")
		(net "M_D_CPU0_SA_CB<6>")
	)
	(segment
		(start 293.559484 -269.992348)
		(end 293.463218 -269.992348)
		(width 0.18288)
		(layer "In11.Cu")
		(net "M_D_CPU0_SA_CB<6>")
	)
	(segment
		(start 317.066676 -265.903964)
		(end 317.38824 -266.680188)
		(width 0.18288)
		(layer "In11.Cu")
		(net "M_D_CPU0_SA_CB<6>")
	)
	(segment
		(start 310.550306 -269.141702)
		(end 308.728618 -269.141702)
		(width 0.18288)
		(layer "In11.Cu")
		(net "M_D_CPU0_SA_CB<6>")
	)
	(segment
		(start 283.69768 -269.142464)
		(end 282.845764 -269.99438)
		(width 0.18288)
		(layer "In11.Cu")
		(net "M_D_CPU0_SA_CB<6>")
	)
	(segment
		(start 272.767806 -271.599914)
		(end 271.712182 -271.599914)
		(width 0.18288)
		(layer "In11.Cu")
		(net "M_D_CPU0_SA_CB<6>")
	)
	(segment
		(start 316.167262 -266.067794)
		(end 315.875924 -266.188698)
		(width 0.18288)
		(layer "In11.Cu")
		(net "M_D_CPU0_SA_CB<6>")
	)
	(segment
		(start 313.237626 -267.564362)
		(end 313.237626 -267.837158)
		(width 0.18288)
		(layer "In11.Cu")
		(net "M_D_CPU0_SA_CB<6>")
	)
	(segment
		(start 313.357514 -267.957046)
		(end 313.357514 -268.229842)
		(width 0.18288)
		(layer "In11.Cu")
		(net "M_D_CPU0_SA_CB<6>")
	)
	(segment
		(start 293.463218 -269.992348)
		(end 293.325296 -269.854426)
		(width 0.18288)
		(layer "In11.Cu")
		(net "M_D_CPU0_SA_CB<6>")
	)
	(segment
		(start 299.379894 -269.016226)
		(end 298.817538 -269.016226)
		(width 0.18288)
		(layer "In11.Cu")
		(net "M_D_CPU0_SA_CB<6>")
	)
	(segment
		(start 312.741818 -268.332966)
		(end 312.469022 -268.332966)
		(width 0.18288)
		(layer "In11.Cu")
		(net "M_D_CPU0_SA_CB<6>")
	)
	(segment
		(start 340.237064 -261.5692)
		(end 340.222332 -261.560564)
		(width 0.088646)
		(layer "In11.Cu")
		(net "M_D_CPU0_SA_CB<6>")
	)
	(segment
		(start 307.019452 -269.035784)
		(end 303.932336 -269.035784)
		(width 0.18288)
		(layer "In11.Cu")
		(net "M_D_CPU0_SA_CB<6>")
	)
	(segment
		(start 276.608032 -270.770604)
		(end 273.597116 -270.770604)
		(width 0.18288)
		(layer "In11.Cu")
		(net "M_D_CPU0_SA_CB<6>")
	)
	(segment
		(start 315.518546 -267.66266)
		(end 315.358018 -267.275818)
		(width 0.18288)
		(layer "In11.Cu")
		(net "M_D_CPU0_SA_CB<6>")
	)
	(segment
		(start 314.496196 -267.4239)
		(end 313.378088 -267.4239)
		(width 0.18288)
		(layer "In11.Cu")
		(net "M_D_CPU0_SA_CB<6>")
	)
	(arc
		(start 345.875864 -261.5692)
		(mid 345.593162 -261.493424)
		(end 345.31046 -261.5692)
		(width 0.088646)
		(layer "In11.Cu")
		(net "M_D_CPU0_SA_CB<6>")
	)
	(arc
		(start 340.61146 -261.5692)
		(mid 340.424262 -261.619343)
		(end 340.237064 -261.5692)
		(width 0.088646)
		(layer "In11.Cu")
		(net "M_D_CPU0_SA_CB<6>")
	)
	(arc
		(start 341.55126 -261.5692)
		(mid 341.364062 -261.619343)
		(end 341.176864 -261.5692)
		(width 0.088646)
		(layer "In11.Cu")
		(net "M_D_CPU0_SA_CB<6>")
	)
	(arc
		(start 343.041732 -261.560564)
		(mid 342.765257 -261.493244)
		(end 342.49106 -261.5692)
		(width 0.088646)
		(layer "In11.Cu")
		(net "M_D_CPU0_SA_CB<6>")
	)
	(arc
		(start 339.297264 -261.5692)
		(mid 339.014562 -261.493424)
		(end 338.73186 -261.5692)
		(width 0.088646)
		(layer "In11.Cu")
		(net "M_D_CPU0_SA_CB<6>")
	)
	(arc
		(start 333.09306 -261.5692)
		(mid 332.905862 -261.619343)
		(end 332.718664 -261.5692)
		(width 0.088646)
		(layer "In11.Cu")
		(net "M_D_CPU0_SA_CB<6>")
	)
	(arc
		(start 338.357464 -261.5692)
		(mid 338.074762 -261.493424)
		(end 337.79206 -261.5692)
		(width 0.088646)
		(layer "In11.Cu")
		(net "M_D_CPU0_SA_CB<6>")
	)
	(arc
		(start 344.921332 -261.560564)
		(mid 344.644857 -261.493244)
		(end 344.37066 -261.5692)
		(width 0.088646)
		(layer "In11.Cu")
		(net "M_D_CPU0_SA_CB<6>")
	)
	(arc
		(start 334.03286 -261.5692)
		(mid 333.845662 -261.619343)
		(end 333.658464 -261.5692)
		(width 0.088646)
		(layer "In11.Cu")
		(net "M_D_CPU0_SA_CB<6>")
	)
	(arc
		(start 334.598264 -261.5692)
		(mid 334.315562 -261.493424)
		(end 334.03286 -261.5692)
		(width 0.088646)
		(layer "In11.Cu")
		(net "M_D_CPU0_SA_CB<6>")
	)
	(arc
		(start 344.37066 -261.5692)
		(mid 344.183462 -261.619343)
		(end 343.996264 -261.5692)
		(width 0.088646)
		(layer "In11.Cu")
		(net "M_D_CPU0_SA_CB<6>")
	)
	(arc
		(start 338.73186 -261.5692)
		(mid 338.544662 -261.619343)
		(end 338.357464 -261.5692)
		(width 0.088646)
		(layer "In11.Cu")
		(net "M_D_CPU0_SA_CB<6>")
	)
	(arc
		(start 333.658464 -261.5692)
		(mid 333.375762 -261.493424)
		(end 333.09306 -261.5692)
		(width 0.088646)
		(layer "In11.Cu")
		(net "M_D_CPU0_SA_CB<6>")
	)
	(arc
		(start 337.79206 -261.5692)
		(mid 337.611116 -261.619291)
		(end 337.428586 -261.575296)
		(width 0.088646)
		(layer "In11.Cu")
		(net "M_D_CPU0_SA_CB<6>")
	)
	(arc
		(start 332.718664 -261.5692)
		(mid 332.435962 -261.493424)
		(end 332.15326 -261.5692)
		(width 0.088646)
		(layer "In11.Cu")
		(net "M_D_CPU0_SA_CB<6>")
	)
	(arc
		(start 335.538064 -261.5692)
		(mid 335.255362 -261.493424)
		(end 334.97266 -261.5692)
		(width 0.088646)
		(layer "In11.Cu")
		(net "M_D_CPU0_SA_CB<6>")
	)
	(arc
		(start 341.162132 -261.560564)
		(mid 340.885657 -261.493244)
		(end 340.61146 -261.5692)
		(width 0.088646)
		(layer "In11.Cu")
		(net "M_D_CPU0_SA_CB<6>")
	)
	(arc
		(start 332.15326 -261.5692)
		(mid 332.062988 -261.606799)
		(end 331.966062 -261.619746)
		(width 0.088646)
		(layer "In11.Cu")
		(net "M_D_CPU0_SA_CB<6>")
	)
	(arc
		(start 343.981532 -261.560564)
		(mid 343.705057 -261.493244)
		(end 343.43086 -261.5692)
		(width 0.088646)
		(layer "In11.Cu")
		(net "M_D_CPU0_SA_CB<6>")
	)
	(arc
		(start 336.85226 -261.5692)
		(mid 336.665062 -261.619343)
		(end 336.477864 -261.5692)
		(width 0.088646)
		(layer "In11.Cu")
		(net "M_D_CPU0_SA_CB<6>")
	)
	(arc
		(start 340.222332 -261.560564)
		(mid 339.945857 -261.493244)
		(end 339.67166 -261.5692)
		(width 0.088646)
		(layer "In11.Cu")
		(net "M_D_CPU0_SA_CB<6>")
	)
	(arc
		(start 336.477864 -261.5692)
		(mid 336.195162 -261.493424)
		(end 335.91246 -261.5692)
		(width 0.088646)
		(layer "In11.Cu")
		(net "M_D_CPU0_SA_CB<6>")
	)
	(arc
		(start 339.67166 -261.5692)
		(mid 339.484462 -261.619343)
		(end 339.297264 -261.5692)
		(width 0.088646)
		(layer "In11.Cu")
		(net "M_D_CPU0_SA_CB<6>")
	)
	(arc
		(start 343.43086 -261.5692)
		(mid 343.243662 -261.619343)
		(end 343.056464 -261.5692)
		(width 0.088646)
		(layer "In11.Cu")
		(net "M_D_CPU0_SA_CB<6>")
	)
	(arc
		(start 337.402932 -261.56031)
		(mid 337.126457 -261.49299)
		(end 336.85226 -261.568946)
		(width 0.088646)
		(layer "In11.Cu")
		(net "M_D_CPU0_SA_CB<6>")
	)
	(arc
		(start 335.91246 -261.5692)
		(mid 335.725262 -261.619343)
		(end 335.538064 -261.5692)
		(width 0.088646)
		(layer "In11.Cu")
		(net "M_D_CPU0_SA_CB<6>")
	)
	(arc
		(start 342.49106 -261.5692)
		(mid 342.303862 -261.619343)
		(end 342.116664 -261.5692)
		(width 0.088646)
		(layer "In11.Cu")
		(net "M_D_CPU0_SA_CB<6>")
	)
	(arc
		(start 348.412816 -262.058658)
		(mid 347.932337 -261.737612)
		(end 347.365574 -261.624826)
		(width 0.088646)
		(layer "In11.Cu")
		(net "M_D_CPU0_SA_CB<6>")
	)
	(arc
		(start 334.97266 -261.5692)
		(mid 334.785462 -261.619343)
		(end 334.598264 -261.5692)
		(width 0.088646)
		(layer "In11.Cu")
		(net "M_D_CPU0_SA_CB<6>")
	)
	(arc
		(start 345.31046 -261.5692)
		(mid 345.123262 -261.619343)
		(end 344.936064 -261.5692)
		(width 0.088646)
		(layer "In11.Cu")
		(net "M_D_CPU0_SA_CB<6>")
	)
	(arc
		(start 342.101932 -261.560564)
		(mid 341.825457 -261.493244)
		(end 341.55126 -261.5692)
		(width 0.088646)
		(layer "In11.Cu")
		(net "M_D_CPU0_SA_CB<6>")
	)
	(segment
		(start 347.003116 -261.244588)
		(end 347.002862 -261.244842)
		(width 0.20066)
		(layer "F.Cu")
		(net "M_D_CPU0_SA_CB<5>")
	)
	(segment
		(start 263.624314 -271.266666)
		(end 261.984998 -271.266666)
		(width 0.20066)
		(layer "F.Cu")
		(net "M_D_CPU0_SA_CB<5>")
	)
	(segment
		(start 347.003116 -260.708902)
		(end 347.003116 -261.244588)
		(width 0.20066)
		(layer "F.Cu")
		(net "M_D_CPU0_SA_CB<5>")
	)
	(segment
		(start 261.050786 -270.841724)
		(end 259.065268 -270.841724)
		(width 0.1016)
		(layer "F.Cu")
		(net "M_D_CPU0_SA_CB<5>")
	)
	(segment
		(start 257.414776 -271.266666)
		(end 256.080514 -271.266666)
		(width 0.20066)
		(layer "F.Cu")
		(net "M_D_CPU0_SA_CB<5>")
	)
	(segment
		(start 258.28498 -271.323562)
		(end 258.130548 -271.477994)
		(width 0.20066)
		(layer "F.Cu")
		(net "M_D_CPU0_SA_CB<5>")
	)
	(segment
		(start 259.056378 -270.832834)
		(end 258.44754 -270.832834)
		(width 0.20066)
		(layer "F.Cu")
		(net "M_D_CPU0_SA_CB<5>")
	)
	(segment
		(start 258.28498 -270.995394)
		(end 258.28498 -271.323562)
		(width 0.20066)
		(layer "F.Cu")
		(net "M_D_CPU0_SA_CB<5>")
	)
	(segment
		(start 258.44754 -270.832834)
		(end 258.28498 -270.995394)
		(width 0.20066)
		(layer "F.Cu")
		(net "M_D_CPU0_SA_CB<5>")
	)
	(segment
		(start 257.626104 -271.477994)
		(end 257.414776 -271.266666)
		(width 0.20066)
		(layer "F.Cu")
		(net "M_D_CPU0_SA_CB<5>")
	)
	(segment
		(start 258.130548 -271.477994)
		(end 257.626104 -271.477994)
		(width 0.20066)
		(layer "F.Cu")
		(net "M_D_CPU0_SA_CB<5>")
	)
	(segment
		(start 259.065268 -270.841724)
		(end 259.056378 -270.832834)
		(width 0.1016)
		(layer "F.Cu")
		(net "M_D_CPU0_SA_CB<5>")
	)
	(segment
		(start 261.984998 -271.266666)
		(end 261.560056 -270.841724)
		(width 0.20066)
		(layer "F.Cu")
		(net "M_D_CPU0_SA_CB<5>")
	)
	(segment
		(start 261.381494 -270.841724)
		(end 261.050786 -270.841724)
		(width 0.101854)
		(layer "F.Cu")
		(net "M_D_CPU0_SA_CB<5>")
	)
	(segment
		(start 264.729214 -271.266666)
		(end 263.624314 -271.266666)
		(width 0.20066)
		(layer "F.Cu")
		(net "M_D_CPU0_SA_CB<5>")
	)
	(segment
		(start 261.560056 -270.841724)
		(end 261.381494 -270.841724)
		(width 0.20066)
		(layer "F.Cu")
		(net "M_D_CPU0_SA_CB<5>")
	)
	(segment
		(start 308.853078 -268.413738)
		(end 308.42077 -268.413738)
		(width 0.18288)
		(layer "In11.Cu")
		(net "M_D_CPU0_SA_CB<5>")
	)
	(segment
		(start 315.074808 -265.908028)
		(end 314.191142 -266.791694)
		(width 0.18288)
		(layer "In11.Cu")
		(net "M_D_CPU0_SA_CB<5>")
	)
	(segment
		(start 273.321526 -270.227806)
		(end 272.554446 -270.994886)
		(width 0.18288)
		(layer "In11.Cu")
		(net "M_D_CPU0_SA_CB<5>")
	)
	(segment
		(start 271.58569 -270.994886)
		(end 271.07515 -271.505426)
		(width 0.18288)
		(layer "In11.Cu")
		(net "M_D_CPU0_SA_CB<5>")
	)
	(segment
		(start 277.34006 -269.288006)
		(end 276.40026 -270.227806)
		(width 0.18288)
		(layer "In11.Cu")
		(net "M_D_CPU0_SA_CB<5>")
	)
	(segment
		(start 269.287498 -271.505426)
		(end 269.100554 -271.69237)
		(width 0.18288)
		(layer "In11.Cu")
		(net "M_D_CPU0_SA_CB<5>")
	)
	(segment
		(start 308.42077 -268.413738)
		(end 308.159658 -268.152626)
		(width 0.18288)
		(layer "In11.Cu")
		(net "M_D_CPU0_SA_CB<5>")
	)
	(segment
		(start 278.483314 -269.288006)
		(end 277.34006 -269.288006)
		(width 0.18288)
		(layer "In11.Cu")
		(net "M_D_CPU0_SA_CB<5>")
	)
	(segment
		(start 265.812016 -271.88541)
		(end 265.618976 -271.69237)
		(width 0.18288)
		(layer "In11.Cu")
		(net "M_D_CPU0_SA_CB<5>")
	)
	(segment
		(start 276.40026 -270.227806)
		(end 273.321526 -270.227806)
		(width 0.18288)
		(layer "In11.Cu")
		(net "M_D_CPU0_SA_CB<5>")
	)
	(segment
		(start 302.885094 -269.244826)
		(end 301.767494 -269.244826)
		(width 0.18288)
		(layer "In11.Cu")
		(net "M_D_CPU0_SA_CB<5>")
	)
	(segment
		(start 301.767494 -269.244826)
		(end 300.73981 -268.217142)
		(width 0.18288)
		(layer "In11.Cu")
		(net "M_D_CPU0_SA_CB<5>")
	)
	(segment
		(start 266.706096 -271.69237)
		(end 266.513056 -271.88541)
		(width 0.18288)
		(layer "In11.Cu")
		(net "M_D_CPU0_SA_CB<5>")
	)
	(segment
		(start 288.800794 -269.206726)
		(end 286.565594 -269.206726)
		(width 0.18288)
		(layer "In11.Cu")
		(net "M_D_CPU0_SA_CB<5>")
	)
	(segment
		(start 339.297264 -260.920484)
		(end 339.282532 -260.92912)
		(width 0.088646)
		(layer "In11.Cu")
		(net "M_D_CPU0_SA_CB<5>")
	)
	(segment
		(start 266.513056 -272.325846)
		(end 266.320016 -272.518886)
		(width 0.18288)
		(layer "In11.Cu")
		(net "M_D_CPU0_SA_CB<5>")
	)
	(segment
		(start 299.659294 -268.330426)
		(end 298.764706 -268.330426)
		(width 0.18288)
		(layer "In11.Cu")
		(net "M_D_CPU0_SA_CB<5>")
	)
	(segment
		(start 331.7113 -260.869684)
		(end 331.361034 -261.21995)
		(width 0.088646)
		(layer "In11.Cu")
		(net "M_D_CPU0_SA_CB<5>")
	)
	(segment
		(start 271.07515 -271.505426)
		(end 269.287498 -271.505426)
		(width 0.18288)
		(layer "In11.Cu")
		(net "M_D_CPU0_SA_CB<5>")
	)
	(segment
		(start 298.764706 -268.330426)
		(end 298.205906 -268.889226)
		(width 0.18288)
		(layer "In11.Cu")
		(net "M_D_CPU0_SA_CB<5>")
	)
	(segment
		(start 347.315536 -261.244842)
		(end 347.37294 -261.187438)
		(width 0.088646)
		(layer "In11.Cu")
		(net "M_D_CPU0_SA_CB<5>")
	)
	(segment
		(start 283.73451 -268.292326)
		(end 282.886912 -269.139924)
		(width 0.18288)
		(layer "In11.Cu")
		(net "M_D_CPU0_SA_CB<5>")
	)
	(segment
		(start 322.330572 -261.21995)
		(end 319.458086 -264.092436)
		(width 0.18288)
		(layer "In11.Cu")
		(net "M_D_CPU0_SA_CB<5>")
	)
	(segment
		(start 267.915136 -271.88541)
		(end 267.915136 -272.325846)
		(width 0.18288)
		(layer "In11.Cu")
		(net "M_D_CPU0_SA_CB<5>")
	)
	(segment
		(start 342.505792 -260.92912)
		(end 342.49106 -260.920484)
		(width 0.088646)
		(layer "In11.Cu")
		(net "M_D_CPU0_SA_CB<5>")
	)
	(segment
		(start 265.812016 -272.325846)
		(end 265.812016 -271.88541)
		(width 0.18288)
		(layer "In11.Cu")
		(net "M_D_CPU0_SA_CB<5>")
	)
	(segment
		(start 269.100554 -271.69237)
		(end 268.108176 -271.69237)
		(width 0.18288)
		(layer "In11.Cu")
		(net "M_D_CPU0_SA_CB<5>")
	)
	(segment
		(start 337.417664 -260.920484)
		(end 337.402932 -260.92912)
		(width 0.088646)
		(layer "In11.Cu")
		(net "M_D_CPU0_SA_CB<5>")
	)
	(segment
		(start 289.169094 -268.838426)
		(end 288.800794 -269.206726)
		(width 0.18288)
		(layer "In11.Cu")
		(net "M_D_CPU0_SA_CB<5>")
	)
	(segment
		(start 292.54323 -269.346426)
		(end 292.03523 -268.838426)
		(width 0.18288)
		(layer "In11.Cu")
		(net "M_D_CPU0_SA_CB<5>")
	)
	(segment
		(start 286.565594 -269.206726)
		(end 285.536894 -268.178026)
		(width 0.18288)
		(layer "In11.Cu")
		(net "M_D_CPU0_SA_CB<5>")
	)
	(segment
		(start 278.631396 -269.139924)
		(end 278.483314 -269.288006)
		(width 0.18288)
		(layer "In11.Cu")
		(net "M_D_CPU0_SA_CB<5>")
	)
	(segment
		(start 296.30751 -269.14221)
		(end 293.51351 -269.14221)
		(width 0.18288)
		(layer "In11.Cu")
		(net "M_D_CPU0_SA_CB<5>")
	)
	(segment
		(start 308.159658 -268.152626)
		(end 307.457094 -268.152626)
		(width 0.18288)
		(layer "In11.Cu")
		(net "M_D_CPU0_SA_CB<5>")
	)
	(segment
		(start 272.554446 -270.994886)
		(end 271.58569 -270.994886)
		(width 0.18288)
		(layer "In11.Cu")
		(net "M_D_CPU0_SA_CB<5>")
	)
	(segment
		(start 299.772578 -268.217142)
		(end 299.659294 -268.330426)
		(width 0.18288)
		(layer "In11.Cu")
		(net "M_D_CPU0_SA_CB<5>")
	)
	(segment
		(start 311.509918 -267.390626)
		(end 310.747918 -268.152626)
		(width 0.18288)
		(layer "In11.Cu")
		(net "M_D_CPU0_SA_CB<5>")
	)
	(segment
		(start 343.996264 -260.920484)
		(end 343.981532 -260.92912)
		(width 0.088646)
		(layer "In11.Cu")
		(net "M_D_CPU0_SA_CB<5>")
	)
	(segment
		(start 347.19895 -260.925564)
		(end 347.19006 -260.920484)
		(width 0.088646)
		(layer "In11.Cu")
		(net "M_D_CPU0_SA_CB<5>")
	)
	(segment
		(start 309.11419 -268.152626)
		(end 308.853078 -268.413738)
		(width 0.18288)
		(layer "In11.Cu")
		(net "M_D_CPU0_SA_CB<5>")
	)
	(segment
		(start 267.214096 -272.325846)
		(end 267.214096 -271.88541)
		(width 0.18288)
		(layer "In11.Cu")
		(net "M_D_CPU0_SA_CB<5>")
	)
	(segment
		(start 330.953618 -261.21995)
		(end 322.330572 -261.21995)
		(width 0.18288)
		(layer "In11.Cu")
		(net "M_D_CPU0_SA_CB<5>")
	)
	(segment
		(start 268.108176 -271.69237)
		(end 267.915136 -271.88541)
		(width 0.18288)
		(layer "In11.Cu")
		(net "M_D_CPU0_SA_CB<5>")
	)
	(segment
		(start 292.03523 -268.838426)
		(end 289.169094 -268.838426)
		(width 0.18288)
		(layer "In11.Cu")
		(net "M_D_CPU0_SA_CB<5>")
	)
	(segment
		(start 284.762194 -268.292326)
		(end 283.73451 -268.292326)
		(width 0.18288)
		(layer "In11.Cu")
		(net "M_D_CPU0_SA_CB<5>")
	)
	(segment
		(start 266.320016 -272.518886)
		(end 266.005056 -272.518886)
		(width 0.18288)
		(layer "In11.Cu")
		(net "M_D_CPU0_SA_CB<5>")
	)
	(segment
		(start 285.536894 -268.178026)
		(end 284.876494 -268.178026)
		(width 0.18288)
		(layer "In11.Cu")
		(net "M_D_CPU0_SA_CB<5>")
	)
	(segment
		(start 267.722096 -272.518886)
		(end 267.407136 -272.518886)
		(width 0.18288)
		(layer "In11.Cu")
		(net "M_D_CPU0_SA_CB<5>")
	)
	(segment
		(start 312.43524 -267.390626)
		(end 311.509918 -267.390626)
		(width 0.18288)
		(layer "In11.Cu")
		(net "M_D_CPU0_SA_CB<5>")
	)
	(segment
		(start 267.214096 -271.88541)
		(end 267.021056 -271.69237)
		(width 0.18288)
		(layer "In11.Cu")
		(net "M_D_CPU0_SA_CB<5>")
	)
	(segment
		(start 345.875864 -260.920484)
		(end 345.861132 -260.92912)
		(width 0.088646)
		(layer "In11.Cu")
		(net "M_D_CPU0_SA_CB<5>")
	)
	(segment
		(start 310.747918 -268.152626)
		(end 309.11419 -268.152626)
		(width 0.18288)
		(layer "In11.Cu")
		(net "M_D_CPU0_SA_CB<5>")
	)
	(segment
		(start 293.51351 -269.14221)
		(end 293.309294 -269.346426)
		(width 0.18288)
		(layer "In11.Cu")
		(net "M_D_CPU0_SA_CB<5>")
	)
	(segment
		(start 331.361034 -261.21995)
		(end 330.953618 -261.21995)
		(width 0.088646)
		(layer "In11.Cu")
		(net "M_D_CPU0_SA_CB<5>")
	)
	(segment
		(start 265.618976 -271.69237)
		(end 265.154918 -271.69237)
		(width 0.18288)
		(layer "In11.Cu")
		(net "M_D_CPU0_SA_CB<5>")
	)
	(segment
		(start 314.191142 -266.791694)
		(end 313.034172 -266.791694)
		(width 0.18288)
		(layer "In11.Cu")
		(net "M_D_CPU0_SA_CB<5>")
	)
	(segment
		(start 266.005056 -272.518886)
		(end 265.812016 -272.325846)
		(width 0.18288)
		(layer "In11.Cu")
		(net "M_D_CPU0_SA_CB<5>")
	)
	(segment
		(start 319.458086 -264.092436)
		(end 315.074808 -265.908028)
		(width 0.18288)
		(layer "In11.Cu")
		(net "M_D_CPU0_SA_CB<5>")
	)
	(segment
		(start 307.457094 -268.152626)
		(end 307.126894 -268.482826)
		(width 0.18288)
		(layer "In11.Cu")
		(net "M_D_CPU0_SA_CB<5>")
	)
	(segment
		(start 284.876494 -268.178026)
		(end 284.762194 -268.292326)
		(width 0.18288)
		(layer "In11.Cu")
		(net "M_D_CPU0_SA_CB<5>")
	)
	(segment
		(start 267.407136 -272.518886)
		(end 267.214096 -272.325846)
		(width 0.18288)
		(layer "In11.Cu")
		(net "M_D_CPU0_SA_CB<5>")
	)
	(segment
		(start 300.73981 -268.217142)
		(end 299.772578 -268.217142)
		(width 0.18288)
		(layer "In11.Cu")
		(net "M_D_CPU0_SA_CB<5>")
	)
	(segment
		(start 313.034172 -266.791694)
		(end 312.43524 -267.390626)
		(width 0.18288)
		(layer "In11.Cu")
		(net "M_D_CPU0_SA_CB<5>")
	)
	(segment
		(start 303.647094 -268.482826)
		(end 302.885094 -269.244826)
		(width 0.18288)
		(layer "In11.Cu")
		(net "M_D_CPU0_SA_CB<5>")
	)
	(segment
		(start 342.116664 -260.920484)
		(end 342.101932 -260.92912)
		(width 0.088646)
		(layer "In11.Cu")
		(net "M_D_CPU0_SA_CB<5>")
	)
	(segment
		(start 293.309294 -269.346426)
		(end 292.54323 -269.346426)
		(width 0.18288)
		(layer "In11.Cu")
		(net "M_D_CPU0_SA_CB<5>")
	)
	(segment
		(start 282.886912 -269.139924)
		(end 278.631396 -269.139924)
		(width 0.18288)
		(layer "In11.Cu")
		(net "M_D_CPU0_SA_CB<5>")
	)
	(segment
		(start 341.176864 -260.920484)
		(end 341.162132 -260.92912)
		(width 0.088646)
		(layer "In11.Cu")
		(net "M_D_CPU0_SA_CB<5>")
	)
	(segment
		(start 298.205906 -268.889226)
		(end 296.560494 -268.889226)
		(width 0.18288)
		(layer "In11.Cu")
		(net "M_D_CPU0_SA_CB<5>")
	)
	(segment
		(start 267.915136 -272.325846)
		(end 267.722096 -272.518886)
		(width 0.18288)
		(layer "In11.Cu")
		(net "M_D_CPU0_SA_CB<5>")
	)
	(segment
		(start 267.021056 -271.69237)
		(end 266.706096 -271.69237)
		(width 0.18288)
		(layer "In11.Cu")
		(net "M_D_CPU0_SA_CB<5>")
	)
	(segment
		(start 331.966062 -260.869684)
		(end 331.7113 -260.869684)
		(width 0.088646)
		(layer "In11.Cu")
		(net "M_D_CPU0_SA_CB<5>")
	)
	(segment
		(start 265.154918 -271.69237)
		(end 264.729214 -271.266666)
		(width 0.18288)
		(layer "In11.Cu")
		(net "M_D_CPU0_SA_CB<5>")
	)
	(segment
		(start 347.002862 -261.244842)
		(end 347.315536 -261.244842)
		(width 0.088646)
		(layer "In11.Cu")
		(net "M_D_CPU0_SA_CB<5>")
	)
	(segment
		(start 296.560494 -268.889226)
		(end 296.30751 -269.14221)
		(width 0.18288)
		(layer "In11.Cu")
		(net "M_D_CPU0_SA_CB<5>")
	)
	(segment
		(start 266.513056 -271.88541)
		(end 266.513056 -272.325846)
		(width 0.18288)
		(layer "In11.Cu")
		(net "M_D_CPU0_SA_CB<5>")
	)
	(segment
		(start 344.385392 -260.92912)
		(end 344.37066 -260.920484)
		(width 0.088646)
		(layer "In11.Cu")
		(net "M_D_CPU0_SA_CB<5>")
	)
	(segment
		(start 307.126894 -268.482826)
		(end 303.647094 -268.482826)
		(width 0.18288)
		(layer "In11.Cu")
		(net "M_D_CPU0_SA_CB<5>")
	)
	(arc
		(start 332.15326 -260.920484)
		(mid 332.063004 -260.882762)
		(end 331.966062 -260.869684)
		(width 0.088646)
		(layer "In11.Cu")
		(net "M_D_CPU0_SA_CB<5>")
	)
	(arc
		(start 346.25026 -260.920484)
		(mid 346.063062 -260.870341)
		(end 345.875864 -260.920484)
		(width 0.088646)
		(layer "In11.Cu")
		(net "M_D_CPU0_SA_CB<5>")
	)
	(arc
		(start 346.815664 -260.920484)
		(mid 346.532962 -260.996226)
		(end 346.25026 -260.920484)
		(width 0.088646)
		(layer "In11.Cu")
		(net "M_D_CPU0_SA_CB<5>")
	)
	(arc
		(start 340.237064 -260.920484)
		(mid 339.954362 -260.996226)
		(end 339.67166 -260.920484)
		(width 0.088646)
		(layer "In11.Cu")
		(net "M_D_CPU0_SA_CB<5>")
	)
	(arc
		(start 336.85226 -260.920484)
		(mid 336.665062 -260.870341)
		(end 336.477864 -260.920484)
		(width 0.088646)
		(layer "In11.Cu")
		(net "M_D_CPU0_SA_CB<5>")
	)
	(arc
		(start 343.981532 -260.92912)
		(mid 343.705091 -260.996286)
		(end 343.43086 -260.920484)
		(width 0.088646)
		(layer "In11.Cu")
		(net "M_D_CPU0_SA_CB<5>")
	)
	(arc
		(start 343.056464 -260.920484)
		(mid 342.782235 -260.996409)
		(end 342.505792 -260.92912)
		(width 0.088646)
		(layer "In11.Cu")
		(net "M_D_CPU0_SA_CB<5>")
	)
	(arc
		(start 340.61146 -260.920484)
		(mid 340.424262 -260.870341)
		(end 340.237064 -260.920484)
		(width 0.088646)
		(layer "In11.Cu")
		(net "M_D_CPU0_SA_CB<5>")
	)
	(arc
		(start 335.538064 -260.920484)
		(mid 335.255362 -260.996226)
		(end 334.97266 -260.920484)
		(width 0.088646)
		(layer "In11.Cu")
		(net "M_D_CPU0_SA_CB<5>")
	)
	(arc
		(start 338.73186 -260.920484)
		(mid 338.544662 -260.870341)
		(end 338.357464 -260.920484)
		(width 0.088646)
		(layer "In11.Cu")
		(net "M_D_CPU0_SA_CB<5>")
	)
	(arc
		(start 345.31046 -260.920484)
		(mid 345.123262 -260.870341)
		(end 344.936064 -260.920484)
		(width 0.088646)
		(layer "In11.Cu")
		(net "M_D_CPU0_SA_CB<5>")
	)
	(arc
		(start 335.91246 -260.920484)
		(mid 335.725262 -260.870341)
		(end 335.538064 -260.920484)
		(width 0.088646)
		(layer "In11.Cu")
		(net "M_D_CPU0_SA_CB<5>")
	)
	(arc
		(start 342.49106 -260.920484)
		(mid 342.303862 -260.870341)
		(end 342.116664 -260.920484)
		(width 0.088646)
		(layer "In11.Cu")
		(net "M_D_CPU0_SA_CB<5>")
	)
	(arc
		(start 337.402932 -260.92912)
		(mid 337.126491 -260.996286)
		(end 336.85226 -260.920484)
		(width 0.088646)
		(layer "In11.Cu")
		(net "M_D_CPU0_SA_CB<5>")
	)
	(arc
		(start 342.101932 -260.92912)
		(mid 341.825491 -260.996286)
		(end 341.55126 -260.920484)
		(width 0.088646)
		(layer "In11.Cu")
		(net "M_D_CPU0_SA_CB<5>")
	)
	(arc
		(start 333.09306 -260.920484)
		(mid 332.905862 -260.870341)
		(end 332.718664 -260.920484)
		(width 0.088646)
		(layer "In11.Cu")
		(net "M_D_CPU0_SA_CB<5>")
	)
	(arc
		(start 347.37294 -261.187438)
		(mid 347.314784 -261.037325)
		(end 347.19895 -260.925564)
		(width 0.088646)
		(layer "In11.Cu")
		(net "M_D_CPU0_SA_CB<5>")
	)
	(arc
		(start 343.43086 -260.920484)
		(mid 343.243662 -260.870341)
		(end 343.056464 -260.920484)
		(width 0.088646)
		(layer "In11.Cu")
		(net "M_D_CPU0_SA_CB<5>")
	)
	(arc
		(start 332.718664 -260.920484)
		(mid 332.435962 -260.996226)
		(end 332.15326 -260.920484)
		(width 0.088646)
		(layer "In11.Cu")
		(net "M_D_CPU0_SA_CB<5>")
	)
	(arc
		(start 344.936064 -260.920484)
		(mid 344.661835 -260.996409)
		(end 344.385392 -260.92912)
		(width 0.088646)
		(layer "In11.Cu")
		(net "M_D_CPU0_SA_CB<5>")
	)
	(arc
		(start 341.55126 -260.920484)
		(mid 341.364062 -260.870341)
		(end 341.176864 -260.920484)
		(width 0.088646)
		(layer "In11.Cu")
		(net "M_D_CPU0_SA_CB<5>")
	)
	(arc
		(start 341.162132 -260.92912)
		(mid 340.885691 -260.996286)
		(end 340.61146 -260.920484)
		(width 0.088646)
		(layer "In11.Cu")
		(net "M_D_CPU0_SA_CB<5>")
	)
	(arc
		(start 334.97266 -260.920484)
		(mid 334.785462 -260.870341)
		(end 334.598264 -260.920484)
		(width 0.088646)
		(layer "In11.Cu")
		(net "M_D_CPU0_SA_CB<5>")
	)
	(arc
		(start 345.861132 -260.92912)
		(mid 345.584691 -260.996286)
		(end 345.31046 -260.920484)
		(width 0.088646)
		(layer "In11.Cu")
		(net "M_D_CPU0_SA_CB<5>")
	)
	(arc
		(start 337.79206 -260.920484)
		(mid 337.604862 -260.870341)
		(end 337.417664 -260.920484)
		(width 0.088646)
		(layer "In11.Cu")
		(net "M_D_CPU0_SA_CB<5>")
	)
	(arc
		(start 344.37066 -260.920484)
		(mid 344.183462 -260.870341)
		(end 343.996264 -260.920484)
		(width 0.088646)
		(layer "In11.Cu")
		(net "M_D_CPU0_SA_CB<5>")
	)
	(arc
		(start 334.03286 -260.920484)
		(mid 333.845662 -260.870341)
		(end 333.658464 -260.920484)
		(width 0.088646)
		(layer "In11.Cu")
		(net "M_D_CPU0_SA_CB<5>")
	)
	(arc
		(start 336.477864 -260.920484)
		(mid 336.195162 -260.996226)
		(end 335.91246 -260.920484)
		(width 0.088646)
		(layer "In11.Cu")
		(net "M_D_CPU0_SA_CB<5>")
	)
	(arc
		(start 347.19006 -260.920484)
		(mid 347.002862 -260.870341)
		(end 346.815664 -260.920484)
		(width 0.088646)
		(layer "In11.Cu")
		(net "M_D_CPU0_SA_CB<5>")
	)
	(arc
		(start 339.282532 -260.92912)
		(mid 339.006091 -260.996286)
		(end 338.73186 -260.920484)
		(width 0.088646)
		(layer "In11.Cu")
		(net "M_D_CPU0_SA_CB<5>")
	)
	(arc
		(start 333.658464 -260.920484)
		(mid 333.375762 -260.996226)
		(end 333.09306 -260.920484)
		(width 0.088646)
		(layer "In11.Cu")
		(net "M_D_CPU0_SA_CB<5>")
	)
	(arc
		(start 334.598264 -260.920484)
		(mid 334.315562 -260.996226)
		(end 334.03286 -260.920484)
		(width 0.088646)
		(layer "In11.Cu")
		(net "M_D_CPU0_SA_CB<5>")
	)
	(arc
		(start 339.67166 -260.920484)
		(mid 339.484462 -260.870341)
		(end 339.297264 -260.920484)
		(width 0.088646)
		(layer "In11.Cu")
		(net "M_D_CPU0_SA_CB<5>")
	)
	(arc
		(start 338.357464 -260.920484)
		(mid 338.074762 -260.996226)
		(end 337.79206 -260.920484)
		(width 0.088646)
		(layer "In11.Cu")
		(net "M_D_CPU0_SA_CB<5>")
	)
	(segment
		(start 346.532962 -261.522718)
		(end 346.532962 -262.058404)
		(width 0.20066)
		(layer "F.Cu")
		(net "M_D_CPU0_SA_CB<4>")
	)
	(segment
		(start 259.056378 -272.533618)
		(end 258.49453 -272.533618)
		(width 0.20066)
		(layer "F.Cu")
		(net "M_D_CPU0_SA_CB<4>")
	)
	(segment
		(start 261.381494 -272.541746)
		(end 259.31241 -272.541746)
		(width 0.1016)
		(layer "F.Cu")
		(net "M_D_CPU0_SA_CB<4>")
	)
	(segment
		(start 258.11226 -273.205448)
		(end 257.653536 -273.205448)
		(width 0.20066)
		(layer "F.Cu")
		(net "M_D_CPU0_SA_CB<4>")
	)
	(segment
		(start 258.28498 -272.743168)
		(end 258.28498 -273.032728)
		(width 0.20066)
		(layer "F.Cu")
		(net "M_D_CPU0_SA_CB<4>")
	)
	(segment
		(start 262.255254 -272.966688)
		(end 261.830312 -272.541746)
		(width 0.20066)
		(layer "F.Cu")
		(net "M_D_CPU0_SA_CB<4>")
	)
	(segment
		(start 258.28498 -273.032728)
		(end 258.11226 -273.205448)
		(width 0.20066)
		(layer "F.Cu")
		(net "M_D_CPU0_SA_CB<4>")
	)
	(segment
		(start 257.414776 -272.966688)
		(end 256.080514 -272.966688)
		(width 0.20066)
		(layer "F.Cu")
		(net "M_D_CPU0_SA_CB<4>")
	)
	(segment
		(start 263.624314 -272.966688)
		(end 262.255254 -272.966688)
		(width 0.20066)
		(layer "F.Cu")
		(net "M_D_CPU0_SA_CB<4>")
	)
	(segment
		(start 259.31241 -272.541746)
		(end 259.064506 -272.541746)
		(width 0.101854)
		(layer "F.Cu")
		(net "M_D_CPU0_SA_CB<4>")
	)
	(segment
		(start 261.830312 -272.541746)
		(end 261.381494 -272.541746)
		(width 0.20066)
		(layer "F.Cu")
		(net "M_D_CPU0_SA_CB<4>")
	)
	(segment
		(start 346.532962 -262.058404)
		(end 346.533216 -262.058658)
		(width 0.20066)
		(layer "F.Cu")
		(net "M_D_CPU0_SA_CB<4>")
	)
	(segment
		(start 264.729214 -272.966688)
		(end 263.624314 -272.966688)
		(width 0.20066)
		(layer "F.Cu")
		(net "M_D_CPU0_SA_CB<4>")
	)
	(segment
		(start 259.064506 -272.541746)
		(end 259.056378 -272.533618)
		(width 0.101854)
		(layer "F.Cu")
		(net "M_D_CPU0_SA_CB<4>")
	)
	(segment
		(start 257.653536 -273.205448)
		(end 257.414776 -272.966688)
		(width 0.20066)
		(layer "F.Cu")
		(net "M_D_CPU0_SA_CB<4>")
	)
	(segment
		(start 258.49453 -272.533618)
		(end 258.28498 -272.743168)
		(width 0.20066)
		(layer "F.Cu")
		(net "M_D_CPU0_SA_CB<4>")
	)
	(segment
		(start 331.678534 -261.809992)
		(end 331.252576 -262.23595)
		(width 0.088646)
		(layer "In11.Cu")
		(net "M_D_CPU0_SA_CB<4>")
	)
	(segment
		(start 266.675108 -273.980402)
		(end 266.360148 -273.980402)
		(width 0.18288)
		(layer "In11.Cu")
		(net "M_D_CPU0_SA_CB<4>")
	)
	(segment
		(start 289.895534 -270.718026)
		(end 289.25012 -270.718026)
		(width 0.18288)
		(layer "In11.Cu")
		(net "M_D_CPU0_SA_CB<4>")
	)
	(segment
		(start 330.953618 -262.23595)
		(end 322.768468 -262.23595)
		(width 0.18288)
		(layer "In11.Cu")
		(net "M_D_CPU0_SA_CB<4>")
	)
	(segment
		(start 265.165586 -273.40306)
		(end 264.729214 -272.966688)
		(width 0.18288)
		(layer "In11.Cu")
		(net "M_D_CPU0_SA_CB<4>")
	)
	(segment
		(start 271.573752 -272.556224)
		(end 270.901414 -273.228562)
		(width 0.18288)
		(layer "In11.Cu")
		(net "M_D_CPU0_SA_CB<4>")
	)
	(segment
		(start 292.496494 -271.073626)
		(end 292.140894 -270.718026)
		(width 0.18288)
		(layer "In11.Cu")
		(net "M_D_CPU0_SA_CB<4>")
	)
	(segment
		(start 309.109872 -270.023082)
		(end 309.109872 -270.239744)
		(width 0.18288)
		(layer "In11.Cu")
		(net "M_D_CPU0_SA_CB<4>")
	)
	(segment
		(start 337.332828 -261.740396)
		(end 337.322414 -261.7343)
		(width 0.088646)
		(layer "In11.Cu")
		(net "M_D_CPU0_SA_CB<4>")
	)
	(segment
		(start 340.156546 -261.742936)
		(end 340.141814 -261.7343)
		(width 0.088646)
		(layer "In11.Cu")
		(net "M_D_CPU0_SA_CB<4>")
	)
	(segment
		(start 283.676852 -269.992348)
		(end 283.071824 -270.597376)
		(width 0.18288)
		(layer "In11.Cu")
		(net "M_D_CPU0_SA_CB<4>")
	)
	(segment
		(start 280.52649 -270.842232)
		(end 279.559512 -270.842232)
		(width 0.18288)
		(layer "In11.Cu")
		(net "M_D_CPU0_SA_CB<4>")
	)
	(segment
		(start 270.901414 -273.228562)
		(end 269.665958 -273.228562)
		(width 0.18288)
		(layer "In11.Cu")
		(net "M_D_CPU0_SA_CB<4>")
	)
	(segment
		(start 272.629884 -272.556224)
		(end 271.573752 -272.556224)
		(width 0.18288)
		(layer "In11.Cu")
		(net "M_D_CPU0_SA_CB<4>")
	)
	(segment
		(start 309.583836 -269.830042)
		(end 309.302912 -269.830042)
		(width 0.18288)
		(layer "In11.Cu")
		(net "M_D_CPU0_SA_CB<4>")
	)
	(segment
		(start 285.450534 -269.879826)
		(end 284.73908 -269.879826)
		(width 0.18288)
		(layer "In11.Cu")
		(net "M_D_CPU0_SA_CB<4>")
	)
	(segment
		(start 331.966062 -261.809992)
		(end 331.678534 -261.809992)
		(width 0.088646)
		(layer "In11.Cu")
		(net "M_D_CPU0_SA_CB<4>")
	)
	(segment
		(start 309.302912 -269.830042)
		(end 309.109872 -270.023082)
		(width 0.18288)
		(layer "In11.Cu")
		(net "M_D_CPU0_SA_CB<4>")
	)
	(segment
		(start 310.717184 -269.994126)
		(end 309.74792 -269.994126)
		(width 0.18288)
		(layer "In11.Cu")
		(net "M_D_CPU0_SA_CB<4>")
	)
	(segment
		(start 311.572148 -269.139162)
		(end 310.717184 -269.994126)
		(width 0.18288)
		(layer "In11.Cu")
		(net "M_D_CPU0_SA_CB<4>")
	)
	(segment
		(start 295.879012 -270.57731)
		(end 295.61409 -270.842232)
		(width 0.18288)
		(layer "In11.Cu")
		(net "M_D_CPU0_SA_CB<4>")
	)
	(segment
		(start 295.61409 -270.842232)
		(end 293.642288 -270.842232)
		(width 0.18288)
		(layer "In11.Cu")
		(net "M_D_CPU0_SA_CB<4>")
	)
	(segment
		(start 277.612094 -271.022826)
		(end 276.929342 -271.705578)
		(width 0.18288)
		(layer "In11.Cu")
		(net "M_D_CPU0_SA_CB<4>")
	)
	(segment
		(start 307.322474 -269.811246)
		(end 307.130196 -270.003524)
		(width 0.18288)
		(layer "In11.Cu")
		(net "M_D_CPU0_SA_CB<4>")
	)
	(segment
		(start 269.665958 -273.228562)
		(end 269.50416 -273.39036)
		(width 0.18288)
		(layer "In11.Cu")
		(net "M_D_CPU0_SA_CB<4>")
	)
	(segment
		(start 303.737772 -270.003524)
		(end 302.88357 -270.857726)
		(width 0.18288)
		(layer "In11.Cu")
		(net "M_D_CPU0_SA_CB<4>")
	)
	(segment
		(start 290.789614 -271.289018)
		(end 290.596574 -271.482058)
		(width 0.18288)
		(layer "In11.Cu")
		(net "M_D_CPU0_SA_CB<4>")
	)
	(segment
		(start 266.167108 -273.5961)
		(end 265.974068 -273.40306)
		(width 0.18288)
		(layer "In11.Cu")
		(net "M_D_CPU0_SA_CB<4>")
	)
	(segment
		(start 273.48053 -271.705578)
		(end 272.629884 -272.556224)
		(width 0.18288)
		(layer "In11.Cu")
		(net "M_D_CPU0_SA_CB<4>")
	)
	(segment
		(start 286.4231 -270.852392)
		(end 285.450534 -269.879826)
		(width 0.18288)
		(layer "In11.Cu")
		(net "M_D_CPU0_SA_CB<4>")
	)
	(segment
		(start 301.589694 -270.857726)
		(end 300.584108 -269.85214)
		(width 0.18288)
		(layer "In11.Cu")
		(net "M_D_CPU0_SA_CB<4>")
	)
	(segment
		(start 299.678852 -269.992348)
		(end 298.826428 -269.992348)
		(width 0.18288)
		(layer "In11.Cu")
		(net "M_D_CPU0_SA_CB<4>")
	)
	(segment
		(start 308.916832 -270.432784)
		(end 308.601872 -270.432784)
		(width 0.18288)
		(layer "In11.Cu")
		(net "M_D_CPU0_SA_CB<4>")
	)
	(segment
		(start 276.929342 -271.705578)
		(end 273.48053 -271.705578)
		(width 0.18288)
		(layer "In11.Cu")
		(net "M_D_CPU0_SA_CB<4>")
	)
	(segment
		(start 290.789614 -270.911066)
		(end 290.789614 -271.289018)
		(width 0.18288)
		(layer "In11.Cu")
		(net "M_D_CPU0_SA_CB<4>")
	)
	(segment
		(start 293.642288 -270.842232)
		(end 293.410894 -271.073626)
		(width 0.18288)
		(layer "In11.Cu")
		(net "M_D_CPU0_SA_CB<4>")
	)
	(segment
		(start 342.975946 -261.742936)
		(end 342.961214 -261.7343)
		(width 0.088646)
		(layer "In11.Cu")
		(net "M_D_CPU0_SA_CB<4>")
	)
	(segment
		(start 346.176854 -261.963154)
		(end 345.78036 -261.7343)
		(width 0.088646)
		(layer "In11.Cu")
		(net "M_D_CPU0_SA_CB<4>")
	)
	(segment
		(start 265.974068 -273.40306)
		(end 265.165586 -273.40306)
		(width 0.18288)
		(layer "In11.Cu")
		(net "M_D_CPU0_SA_CB<4>")
	)
	(segment
		(start 289.25012 -270.718026)
		(end 289.115754 -270.852392)
		(width 0.18288)
		(layer "In11.Cu")
		(net "M_D_CPU0_SA_CB<4>")
	)
	(segment
		(start 266.868148 -273.787362)
		(end 266.675108 -273.980402)
		(width 0.18288)
		(layer "In11.Cu")
		(net "M_D_CPU0_SA_CB<4>")
	)
	(segment
		(start 269.50416 -273.39036)
		(end 267.073888 -273.39036)
		(width 0.18288)
		(layer "In11.Cu")
		(net "M_D_CPU0_SA_CB<4>")
	)
	(segment
		(start 308.601872 -270.432784)
		(end 308.408832 -270.239744)
		(width 0.18288)
		(layer "In11.Cu")
		(net "M_D_CPU0_SA_CB<4>")
	)
	(segment
		(start 309.109872 -270.239744)
		(end 308.916832 -270.432784)
		(width 0.18288)
		(layer "In11.Cu")
		(net "M_D_CPU0_SA_CB<4>")
	)
	(segment
		(start 331.252576 -262.23595)
		(end 330.953618 -262.23595)
		(width 0.088646)
		(layer "In11.Cu")
		(net "M_D_CPU0_SA_CB<4>")
	)
	(segment
		(start 302.88357 -270.857726)
		(end 301.589694 -270.857726)
		(width 0.18288)
		(layer "In11.Cu")
		(net "M_D_CPU0_SA_CB<4>")
	)
	(segment
		(start 308.408832 -270.004286)
		(end 308.215792 -269.811246)
		(width 0.18288)
		(layer "In11.Cu")
		(net "M_D_CPU0_SA_CB<4>")
	)
	(segment
		(start 290.596574 -271.482058)
		(end 290.281614 -271.482058)
		(width 0.18288)
		(layer "In11.Cu")
		(net "M_D_CPU0_SA_CB<4>")
	)
	(segment
		(start 299.81906 -269.85214)
		(end 299.678852 -269.992348)
		(width 0.18288)
		(layer "In11.Cu")
		(net "M_D_CPU0_SA_CB<4>")
	)
	(segment
		(start 284.73908 -269.879826)
		(end 284.626558 -269.992348)
		(width 0.18288)
		(layer "In11.Cu")
		(net "M_D_CPU0_SA_CB<4>")
	)
	(segment
		(start 279.559512 -270.842232)
		(end 279.378918 -271.022826)
		(width 0.18288)
		(layer "In11.Cu")
		(net "M_D_CPU0_SA_CB<4>")
	)
	(segment
		(start 266.167108 -273.787362)
		(end 266.167108 -273.5961)
		(width 0.18288)
		(layer "In11.Cu")
		(net "M_D_CPU0_SA_CB<4>")
	)
	(segment
		(start 339.212174 -261.740396)
		(end 339.20176 -261.7343)
		(width 0.088646)
		(layer "In11.Cu")
		(net "M_D_CPU0_SA_CB<4>")
	)
	(segment
		(start 307.130196 -270.003524)
		(end 303.737772 -270.003524)
		(width 0.18288)
		(layer "In11.Cu")
		(net "M_D_CPU0_SA_CB<4>")
	)
	(segment
		(start 290.982654 -270.718026)
		(end 290.789614 -270.911066)
		(width 0.18288)
		(layer "In11.Cu")
		(net "M_D_CPU0_SA_CB<4>")
	)
	(segment
		(start 267.073888 -273.39036)
		(end 266.868148 -273.5961)
		(width 0.18288)
		(layer "In11.Cu")
		(net "M_D_CPU0_SA_CB<4>")
	)
	(segment
		(start 283.071824 -270.597376)
		(end 280.771346 -270.597376)
		(width 0.18288)
		(layer "In11.Cu")
		(net "M_D_CPU0_SA_CB<4>")
	)
	(segment
		(start 279.378918 -271.022826)
		(end 277.612094 -271.022826)
		(width 0.18288)
		(layer "In11.Cu")
		(net "M_D_CPU0_SA_CB<4>")
	)
	(segment
		(start 289.115754 -270.852392)
		(end 286.4231 -270.852392)
		(width 0.18288)
		(layer "In11.Cu")
		(net "M_D_CPU0_SA_CB<4>")
	)
	(segment
		(start 308.408832 -270.239744)
		(end 308.408832 -270.004286)
		(width 0.18288)
		(layer "In11.Cu")
		(net "M_D_CPU0_SA_CB<4>")
	)
	(segment
		(start 284.626558 -269.992348)
		(end 283.676852 -269.992348)
		(width 0.18288)
		(layer "In11.Cu")
		(net "M_D_CPU0_SA_CB<4>")
	)
	(segment
		(start 344.851228 -261.740396)
		(end 344.840814 -261.7343)
		(width 0.088646)
		(layer "In11.Cu")
		(net "M_D_CPU0_SA_CB<4>")
	)
	(segment
		(start 280.771346 -270.597376)
		(end 280.52649 -270.842232)
		(width 0.18288)
		(layer "In11.Cu")
		(net "M_D_CPU0_SA_CB<4>")
	)
	(segment
		(start 322.768468 -262.23595)
		(end 315.865256 -269.139162)
		(width 0.18288)
		(layer "In11.Cu")
		(net "M_D_CPU0_SA_CB<4>")
	)
	(segment
		(start 290.088574 -271.289018)
		(end 290.088574 -270.911066)
		(width 0.18288)
		(layer "In11.Cu")
		(net "M_D_CPU0_SA_CB<4>")
	)
	(segment
		(start 343.915746 -261.742936)
		(end 343.901014 -261.7343)
		(width 0.088646)
		(layer "In11.Cu")
		(net "M_D_CPU0_SA_CB<4>")
	)
	(segment
		(start 341.096346 -261.742936)
		(end 341.081614 -261.7343)
		(width 0.088646)
		(layer "In11.Cu")
		(net "M_D_CPU0_SA_CB<4>")
	)
	(segment
		(start 309.74792 -269.994126)
		(end 309.583836 -269.830042)
		(width 0.18288)
		(layer "In11.Cu")
		(net "M_D_CPU0_SA_CB<4>")
	)
	(segment
		(start 266.360148 -273.980402)
		(end 266.167108 -273.787362)
		(width 0.18288)
		(layer "In11.Cu")
		(net "M_D_CPU0_SA_CB<4>")
	)
	(segment
		(start 290.088574 -270.911066)
		(end 289.895534 -270.718026)
		(width 0.18288)
		(layer "In11.Cu")
		(net "M_D_CPU0_SA_CB<4>")
	)
	(segment
		(start 315.865256 -269.139162)
		(end 311.572148 -269.139162)
		(width 0.18288)
		(layer "In11.Cu")
		(net "M_D_CPU0_SA_CB<4>")
	)
	(segment
		(start 298.826428 -269.992348)
		(end 298.241466 -270.57731)
		(width 0.18288)
		(layer "In11.Cu")
		(net "M_D_CPU0_SA_CB<4>")
	)
	(segment
		(start 308.215792 -269.811246)
		(end 307.322474 -269.811246)
		(width 0.18288)
		(layer "In11.Cu")
		(net "M_D_CPU0_SA_CB<4>")
	)
	(segment
		(start 290.281614 -271.482058)
		(end 290.088574 -271.289018)
		(width 0.18288)
		(layer "In11.Cu")
		(net "M_D_CPU0_SA_CB<4>")
	)
	(segment
		(start 300.584108 -269.85214)
		(end 299.81906 -269.85214)
		(width 0.18288)
		(layer "In11.Cu")
		(net "M_D_CPU0_SA_CB<4>")
	)
	(segment
		(start 293.410894 -271.073626)
		(end 292.496494 -271.073626)
		(width 0.18288)
		(layer "In11.Cu")
		(net "M_D_CPU0_SA_CB<4>")
	)
	(segment
		(start 298.241466 -270.57731)
		(end 295.879012 -270.57731)
		(width 0.18288)
		(layer "In11.Cu")
		(net "M_D_CPU0_SA_CB<4>")
	)
	(segment
		(start 292.140894 -270.718026)
		(end 290.982654 -270.718026)
		(width 0.18288)
		(layer "In11.Cu")
		(net "M_D_CPU0_SA_CB<4>")
	)
	(segment
		(start 342.036146 -261.742936)
		(end 342.021414 -261.7343)
		(width 0.088646)
		(layer "In11.Cu")
		(net "M_D_CPU0_SA_CB<4>")
	)
	(segment
		(start 336.392774 -261.740396)
		(end 336.38236 -261.7343)
		(width 0.088646)
		(layer "In11.Cu")
		(net "M_D_CPU0_SA_CB<4>")
	)
	(segment
		(start 266.868148 -273.5961)
		(end 266.868148 -273.787362)
		(width 0.18288)
		(layer "In11.Cu")
		(net "M_D_CPU0_SA_CB<4>")
	)
	(arc
		(start 344.466418 -261.7343)
		(mid 344.192219 -261.810135)
		(end 343.915746 -261.742936)
		(width 0.088646)
		(layer "In11.Cu")
		(net "M_D_CPU0_SA_CB<4>")
	)
	(arc
		(start 337.322414 -261.7343)
		(mid 337.135216 -261.684123)
		(end 336.948018 -261.7343)
		(width 0.088646)
		(layer "In11.Cu")
		(net "M_D_CPU0_SA_CB<4>")
	)
	(arc
		(start 343.526618 -261.7343)
		(mid 343.252419 -261.810135)
		(end 342.975946 -261.742936)
		(width 0.088646)
		(layer "In11.Cu")
		(net "M_D_CPU0_SA_CB<4>")
	)
	(arc
		(start 336.38236 -261.7343)
		(mid 336.195162 -261.684157)
		(end 336.007964 -261.7343)
		(width 0.088646)
		(layer "In11.Cu")
		(net "M_D_CPU0_SA_CB<4>")
	)
	(arc
		(start 340.141814 -261.7343)
		(mid 339.954616 -261.684157)
		(end 339.767418 -261.7343)
		(width 0.088646)
		(layer "In11.Cu")
		(net "M_D_CPU0_SA_CB<4>")
	)
	(arc
		(start 339.767418 -261.7343)
		(mid 339.490605 -261.81017)
		(end 339.212174 -261.740396)
		(width 0.088646)
		(layer "In11.Cu")
		(net "M_D_CPU0_SA_CB<4>")
	)
	(arc
		(start 339.20176 -261.7343)
		(mid 339.014562 -261.684157)
		(end 338.827364 -261.7343)
		(width 0.088646)
		(layer "In11.Cu")
		(net "M_D_CPU0_SA_CB<4>")
	)
	(arc
		(start 341.647018 -261.7343)
		(mid 341.372819 -261.810135)
		(end 341.096346 -261.742936)
		(width 0.088646)
		(layer "In11.Cu")
		(net "M_D_CPU0_SA_CB<4>")
	)
	(arc
		(start 336.007964 -261.7343)
		(mid 335.725262 -261.810076)
		(end 335.44256 -261.7343)
		(width 0.088646)
		(layer "In11.Cu")
		(net "M_D_CPU0_SA_CB<4>")
	)
	(arc
		(start 342.961214 -261.7343)
		(mid 342.774016 -261.684157)
		(end 342.586818 -261.7343)
		(width 0.088646)
		(layer "In11.Cu")
		(net "M_D_CPU0_SA_CB<4>")
	)
	(arc
		(start 332.248764 -261.7343)
		(mid 332.112395 -261.790742)
		(end 331.966062 -261.809992)
		(width 0.088646)
		(layer "In11.Cu")
		(net "M_D_CPU0_SA_CB<4>")
	)
	(arc
		(start 333.188564 -261.7343)
		(mid 332.905862 -261.810076)
		(end 332.62316 -261.7343)
		(width 0.088646)
		(layer "In11.Cu")
		(net "M_D_CPU0_SA_CB<4>")
	)
	(arc
		(start 346.533216 -262.058658)
		(mid 346.348745 -262.034371)
		(end 346.176854 -261.963154)
		(width 0.088646)
		(layer "In11.Cu")
		(net "M_D_CPU0_SA_CB<4>")
	)
	(arc
		(start 337.887564 -261.7343)
		(mid 337.611005 -261.810043)
		(end 337.332828 -261.740396)
		(width 0.088646)
		(layer "In11.Cu")
		(net "M_D_CPU0_SA_CB<4>")
	)
	(arc
		(start 344.840814 -261.7343)
		(mid 344.653616 -261.684157)
		(end 344.466418 -261.7343)
		(width 0.088646)
		(layer "In11.Cu")
		(net "M_D_CPU0_SA_CB<4>")
	)
	(arc
		(start 335.068164 -261.7343)
		(mid 334.785462 -261.810076)
		(end 334.50276 -261.7343)
		(width 0.088646)
		(layer "In11.Cu")
		(net "M_D_CPU0_SA_CB<4>")
	)
	(arc
		(start 338.827364 -261.7343)
		(mid 338.544662 -261.810076)
		(end 338.26196 -261.7343)
		(width 0.088646)
		(layer "In11.Cu")
		(net "M_D_CPU0_SA_CB<4>")
	)
	(arc
		(start 335.44256 -261.7343)
		(mid 335.255362 -261.684157)
		(end 335.068164 -261.7343)
		(width 0.088646)
		(layer "In11.Cu")
		(net "M_D_CPU0_SA_CB<4>")
	)
	(arc
		(start 332.62316 -261.7343)
		(mid 332.435962 -261.684157)
		(end 332.248764 -261.7343)
		(width 0.088646)
		(layer "In11.Cu")
		(net "M_D_CPU0_SA_CB<4>")
	)
	(arc
		(start 342.021414 -261.7343)
		(mid 341.834216 -261.684157)
		(end 341.647018 -261.7343)
		(width 0.088646)
		(layer "In11.Cu")
		(net "M_D_CPU0_SA_CB<4>")
	)
	(arc
		(start 333.56296 -261.7343)
		(mid 333.375762 -261.684157)
		(end 333.188564 -261.7343)
		(width 0.088646)
		(layer "In11.Cu")
		(net "M_D_CPU0_SA_CB<4>")
	)
	(arc
		(start 336.948018 -261.7343)
		(mid 336.671205 -261.81017)
		(end 336.392774 -261.740396)
		(width 0.088646)
		(layer "In11.Cu")
		(net "M_D_CPU0_SA_CB<4>")
	)
	(arc
		(start 342.586818 -261.7343)
		(mid 342.312619 -261.810135)
		(end 342.036146 -261.742936)
		(width 0.088646)
		(layer "In11.Cu")
		(net "M_D_CPU0_SA_CB<4>")
	)
	(arc
		(start 343.901014 -261.7343)
		(mid 343.713816 -261.684157)
		(end 343.526618 -261.7343)
		(width 0.088646)
		(layer "In11.Cu")
		(net "M_D_CPU0_SA_CB<4>")
	)
	(arc
		(start 334.50276 -261.7343)
		(mid 334.315562 -261.684157)
		(end 334.128364 -261.7343)
		(width 0.088646)
		(layer "In11.Cu")
		(net "M_D_CPU0_SA_CB<4>")
	)
	(arc
		(start 341.081614 -261.7343)
		(mid 340.894416 -261.684157)
		(end 340.707218 -261.7343)
		(width 0.088646)
		(layer "In11.Cu")
		(net "M_D_CPU0_SA_CB<4>")
	)
	(arc
		(start 345.405964 -261.7343)
		(mid 345.129405 -261.810043)
		(end 344.851228 -261.740396)
		(width 0.088646)
		(layer "In11.Cu")
		(net "M_D_CPU0_SA_CB<4>")
	)
	(arc
		(start 338.26196 -261.7343)
		(mid 338.074762 -261.684157)
		(end 337.887564 -261.7343)
		(width 0.088646)
		(layer "In11.Cu")
		(net "M_D_CPU0_SA_CB<4>")
	)
	(arc
		(start 334.128364 -261.7343)
		(mid 333.845662 -261.810076)
		(end 333.56296 -261.7343)
		(width 0.088646)
		(layer "In11.Cu")
		(net "M_D_CPU0_SA_CB<4>")
	)
	(arc
		(start 345.78036 -261.7343)
		(mid 345.593162 -261.684157)
		(end 345.405964 -261.7343)
		(width 0.088646)
		(layer "In11.Cu")
		(net "M_D_CPU0_SA_CB<4>")
	)
	(arc
		(start 340.707218 -261.7343)
		(mid 340.433019 -261.810135)
		(end 340.156546 -261.742936)
		(width 0.088646)
		(layer "In11.Cu")
		(net "M_D_CPU0_SA_CB<4>")
	)
	(segment
		(start 262.003794 -276.492716)
		(end 261.87781 -276.366732)
		(width 0.20066)
		(layer "F.Cu")
		(net "M_D_CPU0_SA_CB<3>")
	)
	(segment
		(start 261.87781 -276.366732)
		(end 260.180582 -276.366732)
		(width 0.20066)
		(layer "F.Cu")
		(net "M_D_CPU0_SA_CB<3>")
	)
	(segment
		(start 265.518646 -276.490938)
		(end 265.518646 -276.642576)
		(width 0.20066)
		(layer "F.Cu")
		(net "M_D_CPU0_SA_CB<3>")
	)
	(segment
		(start 266.25423 -276.57425)
		(end 266.042394 -276.362414)
		(width 0.20066)
		(layer "F.Cu")
		(net "M_D_CPU0_SA_CB<3>")
	)
	(segment
		(start 265.369548 -276.791674)
		(end 264.825226 -276.791674)
		(width 0.20066)
		(layer "F.Cu")
		(net "M_D_CPU0_SA_CB<3>")
	)
	(segment
		(start 268.829282 -276.366732)
		(end 267.724382 -276.366732)
		(width 0.20066)
		(layer "F.Cu")
		(net "M_D_CPU0_SA_CB<3>")
	)
	(segment
		(start 262.752332 -276.791674)
		(end 262.514334 -276.791674)
		(width 0.101854)
		(layer "F.Cu")
		(net "M_D_CPU0_SA_CB<3>")
	)
	(segment
		(start 265.518646 -276.642576)
		(end 265.369548 -276.791674)
		(width 0.20066)
		(layer "F.Cu")
		(net "M_D_CPU0_SA_CB<3>")
	)
	(segment
		(start 262.514334 -276.791674)
		(end 262.50011 -276.805898)
		(width 0.101854)
		(layer "F.Cu")
		(net "M_D_CPU0_SA_CB<3>")
	)
	(segment
		(start 262.50011 -276.805898)
		(end 262.146288 -276.805898)
		(width 0.20066)
		(layer "F.Cu")
		(net "M_D_CPU0_SA_CB<3>")
	)
	(segment
		(start 267.724382 -276.366732)
		(end 266.90828 -276.366732)
		(width 0.20066)
		(layer "F.Cu")
		(net "M_D_CPU0_SA_CB<3>")
	)
	(segment
		(start 348.412562 -263.150604)
		(end 348.412562 -263.68629)
		(width 0.20066)
		(layer "F.Cu")
		(net "M_D_CPU0_SA_CB<3>")
	)
	(segment
		(start 266.700762 -276.57425)
		(end 266.25423 -276.57425)
		(width 0.20066)
		(layer "F.Cu")
		(net "M_D_CPU0_SA_CB<3>")
	)
	(segment
		(start 264.825226 -276.791674)
		(end 262.752332 -276.791674)
		(width 0.1016)
		(layer "F.Cu")
		(net "M_D_CPU0_SA_CB<3>")
	)
	(segment
		(start 348.412562 -263.68629)
		(end 348.412816 -263.686544)
		(width 0.20066)
		(layer "F.Cu")
		(net "M_D_CPU0_SA_CB<3>")
	)
	(segment
		(start 262.146288 -276.805898)
		(end 262.003794 -276.663404)
		(width 0.20066)
		(layer "F.Cu")
		(net "M_D_CPU0_SA_CB<3>")
	)
	(segment
		(start 265.64717 -276.362414)
		(end 265.518646 -276.490938)
		(width 0.20066)
		(layer "F.Cu")
		(net "M_D_CPU0_SA_CB<3>")
	)
	(segment
		(start 266.042394 -276.362414)
		(end 265.64717 -276.362414)
		(width 0.20066)
		(layer "F.Cu")
		(net "M_D_CPU0_SA_CB<3>")
	)
	(segment
		(start 262.003794 -276.663404)
		(end 262.003794 -276.492716)
		(width 0.20066)
		(layer "F.Cu")
		(net "M_D_CPU0_SA_CB<3>")
	)
	(segment
		(start 266.90828 -276.366732)
		(end 266.700762 -276.57425)
		(width 0.20066)
		(layer "F.Cu")
		(net "M_D_CPU0_SA_CB<3>")
	)
	(segment
		(start 273.903694 -274.782026)
		(end 273.497294 -275.188426)
		(width 0.18288)
		(layer "In11.Cu")
		(net "M_D_CPU0_SA_CB<3>")
	)
	(segment
		(start 286.050736 -274.197572)
		(end 285.156148 -275.09216)
		(width 0.18288)
		(layer "In11.Cu")
		(net "M_D_CPU0_SA_CB<3>")
	)
	(segment
		(start 314.687204 -273.435826)
		(end 311.210198 -273.435826)
		(width 0.18288)
		(layer "In11.Cu")
		(net "M_D_CPU0_SA_CB<3>")
	)
	(segment
		(start 330.953872 -264.406634)
		(end 323.716396 -264.406634)
		(width 0.18288)
		(layer "In11.Cu")
		(net "M_D_CPU0_SA_CB<3>")
	)
	(segment
		(start 344.855546 -264.002266)
		(end 344.840814 -264.010902)
		(width 0.088646)
		(layer "In11.Cu")
		(net "M_D_CPU0_SA_CB<3>")
	)
	(segment
		(start 298.043346 -274.823428)
		(end 296.11066 -274.823428)
		(width 0.18288)
		(layer "In11.Cu")
		(net "M_D_CPU0_SA_CB<3>")
	)
	(segment
		(start 275.548598 -274.975066)
		(end 275.548598 -275.392134)
		(width 0.18288)
		(layer "In11.Cu")
		(net "M_D_CPU0_SA_CB<3>")
	)
	(segment
		(start 295.493694 -275.782024)
		(end 295.333674 -275.942044)
		(width 0.18288)
		(layer "In11.Cu")
		(net "M_D_CPU0_SA_CB<3>")
	)
	(segment
		(start 273.497294 -275.188426)
		(end 272.303494 -275.188426)
		(width 0.18288)
		(layer "In11.Cu")
		(net "M_D_CPU0_SA_CB<3>")
	)
	(segment
		(start 307.008784 -273.389852)
		(end 306.75961 -273.639026)
		(width 0.18288)
		(layer "In11.Cu")
		(net "M_D_CPU0_SA_CB<3>")
	)
	(segment
		(start 340.156546 -264.002266)
		(end 340.141814 -264.010902)
		(width 0.088646)
		(layer "In11.Cu")
		(net "M_D_CPU0_SA_CB<3>")
	)
	(segment
		(start 282.921456 -275.09216)
		(end 282.069032 -275.944584)
		(width 0.18288)
		(layer "In11.Cu")
		(net "M_D_CPU0_SA_CB<3>")
	)
	(segment
		(start 272.303494 -275.188426)
		(end 270.614394 -276.877526)
		(width 0.18288)
		(layer "In11.Cu")
		(net "M_D_CPU0_SA_CB<3>")
	)
	(segment
		(start 302.074834 -274.197572)
		(end 302.074834 -273.817588)
		(width 0.18288)
		(layer "In11.Cu")
		(net "M_D_CPU0_SA_CB<3>")
	)
	(segment
		(start 291.201348 -274.390612)
		(end 286.944816 -274.390612)
		(width 0.18288)
		(layer "In11.Cu")
		(net "M_D_CPU0_SA_CB<3>")
	)
	(segment
		(start 286.751776 -273.835114)
		(end 286.558736 -273.642074)
		(width 0.18288)
		(layer "In11.Cu")
		(net "M_D_CPU0_SA_CB<3>")
	)
	(segment
		(start 301.373794 -274.197572)
		(end 300.479206 -275.09216)
		(width 0.18288)
		(layer "In11.Cu")
		(net "M_D_CPU0_SA_CB<3>")
	)
	(segment
		(start 301.566834 -273.624548)
		(end 301.373794 -273.817588)
		(width 0.18288)
		(layer "In11.Cu")
		(net "M_D_CPU0_SA_CB<3>")
	)
	(segment
		(start 302.267874 -274.390612)
		(end 302.074834 -274.197572)
		(width 0.18288)
		(layer "In11.Cu")
		(net "M_D_CPU0_SA_CB<3>")
	)
	(segment
		(start 301.373794 -273.817588)
		(end 301.373794 -274.197572)
		(width 0.18288)
		(layer "In11.Cu")
		(net "M_D_CPU0_SA_CB<3>")
	)
	(segment
		(start 286.558736 -273.642074)
		(end 286.243776 -273.642074)
		(width 0.18288)
		(layer "In11.Cu")
		(net "M_D_CPU0_SA_CB<3>")
	)
	(segment
		(start 286.050736 -273.835114)
		(end 286.050736 -274.197572)
		(width 0.18288)
		(layer "In11.Cu")
		(net "M_D_CPU0_SA_CB<3>")
	)
	(segment
		(start 331.250036 -264.406634)
		(end 330.953872 -264.406634)
		(width 0.088646)
		(layer "In11.Cu")
		(net "M_D_CPU0_SA_CB<3>")
	)
	(segment
		(start 301.881794 -273.624548)
		(end 301.566834 -273.624548)
		(width 0.18288)
		(layer "In11.Cu")
		(net "M_D_CPU0_SA_CB<3>")
	)
	(segment
		(start 345.87561 -263.95553)
		(end 345.781376 -264.010648)
		(width 0.088646)
		(layer "In11.Cu")
		(net "M_D_CPU0_SA_CB<3>")
	)
	(segment
		(start 275.355558 -275.585174)
		(end 275.040598 -275.585174)
		(width 0.18288)
		(layer "In11.Cu")
		(net "M_D_CPU0_SA_CB<3>")
	)
	(segment
		(start 286.243776 -273.642074)
		(end 286.050736 -273.835114)
		(width 0.18288)
		(layer "In11.Cu")
		(net "M_D_CPU0_SA_CB<3>")
	)
	(segment
		(start 276.469094 -274.782026)
		(end 275.741638 -274.782026)
		(width 0.18288)
		(layer "In11.Cu")
		(net "M_D_CPU0_SA_CB<3>")
	)
	(segment
		(start 275.040598 -275.585174)
		(end 274.847558 -275.392134)
		(width 0.18288)
		(layer "In11.Cu")
		(net "M_D_CPU0_SA_CB<3>")
	)
	(segment
		(start 279.493218 -275.944584)
		(end 278.81326 -275.264626)
		(width 0.18288)
		(layer "In11.Cu")
		(net "M_D_CPU0_SA_CB<3>")
	)
	(segment
		(start 292.126162 -275.315426)
		(end 291.201348 -274.390612)
		(width 0.18288)
		(layer "In11.Cu")
		(net "M_D_CPU0_SA_CB<3>")
	)
	(segment
		(start 342.971374 -264.004806)
		(end 342.96096 -264.010902)
		(width 0.088646)
		(layer "In11.Cu")
		(net "M_D_CPU0_SA_CB<3>")
	)
	(segment
		(start 276.951694 -275.264626)
		(end 276.469094 -274.782026)
		(width 0.18288)
		(layer "In11.Cu")
		(net "M_D_CPU0_SA_CB<3>")
	)
	(segment
		(start 286.944816 -274.390612)
		(end 286.751776 -274.197572)
		(width 0.18288)
		(layer "In11.Cu")
		(net "M_D_CPU0_SA_CB<3>")
	)
	(segment
		(start 341.096346 -264.002266)
		(end 341.081614 -264.010902)
		(width 0.088646)
		(layer "In11.Cu")
		(net "M_D_CPU0_SA_CB<3>")
	)
	(segment
		(start 347.31452 -263.326626)
		(end 346.70746 -263.326626)
		(width 0.088646)
		(layer "In11.Cu")
		(net "M_D_CPU0_SA_CB<3>")
	)
	(segment
		(start 282.069032 -275.944584)
		(end 279.493218 -275.944584)
		(width 0.18288)
		(layer "In11.Cu")
		(net "M_D_CPU0_SA_CB<3>")
	)
	(segment
		(start 275.741638 -274.782026)
		(end 275.548598 -274.975066)
		(width 0.18288)
		(layer "In11.Cu")
		(net "M_D_CPU0_SA_CB<3>")
	)
	(segment
		(start 348.057216 -263.59104)
		(end 347.660214 -263.361932)
		(width 0.088646)
		(layer "In11.Cu")
		(net "M_D_CPU0_SA_CB<3>")
	)
	(segment
		(start 311.164224 -273.389852)
		(end 307.008784 -273.389852)
		(width 0.18288)
		(layer "In11.Cu")
		(net "M_D_CPU0_SA_CB<3>")
	)
	(segment
		(start 295.493694 -275.440394)
		(end 295.493694 -275.782024)
		(width 0.18288)
		(layer "In11.Cu")
		(net "M_D_CPU0_SA_CB<3>")
	)
	(segment
		(start 331.966062 -263.93521)
		(end 331.72146 -263.93521)
		(width 0.088646)
		(layer "In11.Cu")
		(net "M_D_CPU0_SA_CB<3>")
	)
	(segment
		(start 286.751776 -274.197572)
		(end 286.751776 -273.835114)
		(width 0.18288)
		(layer "In11.Cu")
		(net "M_D_CPU0_SA_CB<3>")
	)
	(segment
		(start 270.614394 -276.877526)
		(end 269.340076 -276.877526)
		(width 0.18288)
		(layer "In11.Cu")
		(net "M_D_CPU0_SA_CB<3>")
	)
	(segment
		(start 274.847558 -274.975066)
		(end 274.654518 -274.782026)
		(width 0.18288)
		(layer "In11.Cu")
		(net "M_D_CPU0_SA_CB<3>")
	)
	(segment
		(start 302.844708 -274.390612)
		(end 302.267874 -274.390612)
		(width 0.18288)
		(layer "In11.Cu")
		(net "M_D_CPU0_SA_CB<3>")
	)
	(segment
		(start 300.479206 -275.09216)
		(end 298.312078 -275.09216)
		(width 0.18288)
		(layer "In11.Cu")
		(net "M_D_CPU0_SA_CB<3>")
	)
	(segment
		(start 306.75961 -273.639026)
		(end 303.596294 -273.639026)
		(width 0.18288)
		(layer "In11.Cu")
		(net "M_D_CPU0_SA_CB<3>")
	)
	(segment
		(start 303.596294 -273.639026)
		(end 302.844708 -274.390612)
		(width 0.18288)
		(layer "In11.Cu")
		(net "M_D_CPU0_SA_CB<3>")
	)
	(segment
		(start 274.654518 -274.782026)
		(end 273.903694 -274.782026)
		(width 0.18288)
		(layer "In11.Cu")
		(net "M_D_CPU0_SA_CB<3>")
	)
	(segment
		(start 274.847558 -275.392134)
		(end 274.847558 -274.975066)
		(width 0.18288)
		(layer "In11.Cu")
		(net "M_D_CPU0_SA_CB<3>")
	)
	(segment
		(start 294.238426 -275.942044)
		(end 293.611808 -275.315426)
		(width 0.18288)
		(layer "In11.Cu")
		(net "M_D_CPU0_SA_CB<3>")
	)
	(segment
		(start 311.210198 -273.435826)
		(end 311.164224 -273.389852)
		(width 0.18288)
		(layer "In11.Cu")
		(net "M_D_CPU0_SA_CB<3>")
	)
	(segment
		(start 302.074834 -273.817588)
		(end 301.881794 -273.624548)
		(width 0.18288)
		(layer "In11.Cu")
		(net "M_D_CPU0_SA_CB<3>")
	)
	(segment
		(start 296.11066 -274.823428)
		(end 295.493694 -275.440394)
		(width 0.18288)
		(layer "In11.Cu")
		(net "M_D_CPU0_SA_CB<3>")
	)
	(segment
		(start 293.611808 -275.315426)
		(end 292.126162 -275.315426)
		(width 0.18288)
		(layer "In11.Cu")
		(net "M_D_CPU0_SA_CB<3>")
	)
	(segment
		(start 343.915746 -264.002266)
		(end 343.901014 -264.010902)
		(width 0.088646)
		(layer "In11.Cu")
		(net "M_D_CPU0_SA_CB<3>")
	)
	(segment
		(start 278.81326 -275.264626)
		(end 276.951694 -275.264626)
		(width 0.18288)
		(layer "In11.Cu")
		(net "M_D_CPU0_SA_CB<3>")
	)
	(segment
		(start 285.156148 -275.09216)
		(end 282.921456 -275.09216)
		(width 0.18288)
		(layer "In11.Cu")
		(net "M_D_CPU0_SA_CB<3>")
	)
	(segment
		(start 269.340076 -276.877526)
		(end 268.829282 -276.366732)
		(width 0.18288)
		(layer "In11.Cu")
		(net "M_D_CPU0_SA_CB<3>")
	)
	(segment
		(start 338.272374 -264.004806)
		(end 338.26196 -264.010902)
		(width 0.088646)
		(layer "In11.Cu")
		(net "M_D_CPU0_SA_CB<3>")
	)
	(segment
		(start 342.031828 -264.004806)
		(end 342.021414 -264.010902)
		(width 0.088646)
		(layer "In11.Cu")
		(net "M_D_CPU0_SA_CB<3>")
	)
	(segment
		(start 275.548598 -275.392134)
		(end 275.355558 -275.585174)
		(width 0.18288)
		(layer "In11.Cu")
		(net "M_D_CPU0_SA_CB<3>")
	)
	(segment
		(start 295.333674 -275.942044)
		(end 294.238426 -275.942044)
		(width 0.18288)
		(layer "In11.Cu")
		(net "M_D_CPU0_SA_CB<3>")
	)
	(segment
		(start 323.716396 -264.406634)
		(end 314.687204 -273.435826)
		(width 0.18288)
		(layer "In11.Cu")
		(net "M_D_CPU0_SA_CB<3>")
	)
	(segment
		(start 331.72146 -263.93521)
		(end 331.250036 -264.406634)
		(width 0.088646)
		(layer "In11.Cu")
		(net "M_D_CPU0_SA_CB<3>")
	)
	(segment
		(start 298.312078 -275.09216)
		(end 298.043346 -274.823428)
		(width 0.18288)
		(layer "In11.Cu")
		(net "M_D_CPU0_SA_CB<3>")
	)
	(arc
		(start 345.781376 -264.010648)
		(mid 345.781016 -264.010837)
		(end 345.780614 -264.010902)
		(width 0.088646)
		(layer "In11.Cu")
		(net "M_D_CPU0_SA_CB<3>")
	)
	(arc
		(start 346.159074 -263.663684)
		(mid 346.131296 -263.75904)
		(end 346.065094 -263.833102)
		(width 0.088646)
		(layer "In11.Cu")
		(net "M_D_CPU0_SA_CB<3>")
	)
	(arc
		(start 340.141814 -264.010902)
		(mid 339.954616 -264.061045)
		(end 339.767418 -264.010902)
		(width 0.088646)
		(layer "In11.Cu")
		(net "M_D_CPU0_SA_CB<3>")
	)
	(arc
		(start 347.660214 -263.361932)
		(mid 347.53549 -263.316951)
		(end 347.402912 -263.318244)
		(width 0.088646)
		(layer "In11.Cu")
		(net "M_D_CPU0_SA_CB<3>")
	)
	(arc
		(start 347.402912 -263.318244)
		(mid 347.358913 -263.324511)
		(end 347.31452 -263.326626)
		(width 0.088646)
		(layer "In11.Cu")
		(net "M_D_CPU0_SA_CB<3>")
	)
	(arc
		(start 346.70746 -263.326626)
		(mid 346.662904 -263.325128)
		(end 346.61856 -263.32053)
		(width 0.088646)
		(layer "In11.Cu")
		(net "M_D_CPU0_SA_CB<3>")
	)
	(arc
		(start 335.44256 -264.010902)
		(mid 335.255362 -264.061045)
		(end 335.068164 -264.010902)
		(width 0.088646)
		(layer "In11.Cu")
		(net "M_D_CPU0_SA_CB<3>")
	)
	(arc
		(start 346.32138 -263.37768)
		(mid 346.207169 -263.501921)
		(end 346.159074 -263.663684)
		(width 0.088646)
		(layer "In11.Cu")
		(net "M_D_CPU0_SA_CB<3>")
	)
	(arc
		(start 338.827618 -264.010902)
		(mid 338.550805 -263.935032)
		(end 338.272374 -264.004806)
		(width 0.088646)
		(layer "In11.Cu")
		(net "M_D_CPU0_SA_CB<3>")
	)
	(arc
		(start 343.901014 -264.010902)
		(mid 343.713816 -264.061045)
		(end 343.526618 -264.010902)
		(width 0.088646)
		(layer "In11.Cu")
		(net "M_D_CPU0_SA_CB<3>")
	)
	(arc
		(start 344.840814 -264.010902)
		(mid 344.653616 -264.061045)
		(end 344.466418 -264.010902)
		(width 0.088646)
		(layer "In11.Cu")
		(net "M_D_CPU0_SA_CB<3>")
	)
	(arc
		(start 334.50276 -264.010902)
		(mid 334.315562 -264.061045)
		(end 334.128364 -264.010902)
		(width 0.088646)
		(layer "In11.Cu")
		(net "M_D_CPU0_SA_CB<3>")
	)
	(arc
		(start 332.248764 -264.010902)
		(mid 332.112395 -263.95446)
		(end 331.966062 -263.93521)
		(width 0.088646)
		(layer "In11.Cu")
		(net "M_D_CPU0_SA_CB<3>")
	)
	(arc
		(start 344.466418 -264.010902)
		(mid 344.192219 -263.935067)
		(end 343.915746 -264.002266)
		(width 0.088646)
		(layer "In11.Cu")
		(net "M_D_CPU0_SA_CB<3>")
	)
	(arc
		(start 343.526618 -264.010902)
		(mid 343.249805 -263.935032)
		(end 342.971374 -264.004806)
		(width 0.088646)
		(layer "In11.Cu")
		(net "M_D_CPU0_SA_CB<3>")
	)
	(arc
		(start 339.202014 -264.010902)
		(mid 339.014816 -264.061045)
		(end 338.827618 -264.010902)
		(width 0.088646)
		(layer "In11.Cu")
		(net "M_D_CPU0_SA_CB<3>")
	)
	(arc
		(start 346.587318 -263.315958)
		(mid 346.462629 -263.318656)
		(end 346.345764 -263.362186)
		(width 0.088646)
		(layer "In11.Cu")
		(net "M_D_CPU0_SA_CB<3>")
	)
	(arc
		(start 335.068164 -264.010902)
		(mid 334.785462 -263.935126)
		(end 334.50276 -264.010902)
		(width 0.088646)
		(layer "In11.Cu")
		(net "M_D_CPU0_SA_CB<3>")
	)
	(arc
		(start 346.61856 -263.32053)
		(mid 346.602935 -263.31827)
		(end 346.587318 -263.315958)
		(width 0.088646)
		(layer "In11.Cu")
		(net "M_D_CPU0_SA_CB<3>")
	)
	(arc
		(start 345.406218 -264.010902)
		(mid 345.132019 -263.935067)
		(end 344.855546 -264.002266)
		(width 0.088646)
		(layer "In11.Cu")
		(net "M_D_CPU0_SA_CB<3>")
	)
	(arc
		(start 338.26196 -264.010902)
		(mid 338.074762 -264.061045)
		(end 337.887564 -264.010902)
		(width 0.088646)
		(layer "In11.Cu")
		(net "M_D_CPU0_SA_CB<3>")
	)
	(arc
		(start 339.767418 -264.010902)
		(mid 339.484716 -263.935126)
		(end 339.202014 -264.010902)
		(width 0.088646)
		(layer "In11.Cu")
		(net "M_D_CPU0_SA_CB<3>")
	)
	(arc
		(start 340.707218 -264.010902)
		(mid 340.433019 -263.935067)
		(end 340.156546 -264.002266)
		(width 0.088646)
		(layer "In11.Cu")
		(net "M_D_CPU0_SA_CB<3>")
	)
	(arc
		(start 336.38236 -264.010902)
		(mid 336.195162 -264.061045)
		(end 336.007964 -264.010902)
		(width 0.088646)
		(layer "In11.Cu")
		(net "M_D_CPU0_SA_CB<3>")
	)
	(arc
		(start 336.007964 -264.010902)
		(mid 335.725262 -263.935126)
		(end 335.44256 -264.010902)
		(width 0.088646)
		(layer "In11.Cu")
		(net "M_D_CPU0_SA_CB<3>")
	)
	(arc
		(start 333.56296 -264.010902)
		(mid 333.375762 -264.061045)
		(end 333.188564 -264.010902)
		(width 0.088646)
		(layer "In11.Cu")
		(net "M_D_CPU0_SA_CB<3>")
	)
	(arc
		(start 345.780614 -264.010902)
		(mid 345.593416 -264.061045)
		(end 345.406218 -264.010902)
		(width 0.088646)
		(layer "In11.Cu")
		(net "M_D_CPU0_SA_CB<3>")
	)
	(arc
		(start 333.188564 -264.010902)
		(mid 332.905862 -263.935126)
		(end 332.62316 -264.010902)
		(width 0.088646)
		(layer "In11.Cu")
		(net "M_D_CPU0_SA_CB<3>")
	)
	(arc
		(start 332.62316 -264.010902)
		(mid 332.435962 -264.061045)
		(end 332.248764 -264.010902)
		(width 0.088646)
		(layer "In11.Cu")
		(net "M_D_CPU0_SA_CB<3>")
	)
	(arc
		(start 348.412816 -263.686544)
		(mid 348.228751 -263.662121)
		(end 348.057216 -263.59104)
		(width 0.088646)
		(layer "In11.Cu")
		(net "M_D_CPU0_SA_CB<3>")
	)
	(arc
		(start 346.345764 -263.362186)
		(mid 346.333387 -263.369643)
		(end 346.32138 -263.37768)
		(width 0.088646)
		(layer "In11.Cu")
		(net "M_D_CPU0_SA_CB<3>")
	)
	(arc
		(start 342.586564 -264.010902)
		(mid 342.310005 -263.935159)
		(end 342.031828 -264.004806)
		(width 0.088646)
		(layer "In11.Cu")
		(net "M_D_CPU0_SA_CB<3>")
	)
	(arc
		(start 342.96096 -264.010902)
		(mid 342.773762 -264.061045)
		(end 342.586564 -264.010902)
		(width 0.088646)
		(layer "In11.Cu")
		(net "M_D_CPU0_SA_CB<3>")
	)
	(arc
		(start 341.081614 -264.010902)
		(mid 340.894416 -264.061045)
		(end 340.707218 -264.010902)
		(width 0.088646)
		(layer "In11.Cu")
		(net "M_D_CPU0_SA_CB<3>")
	)
	(arc
		(start 341.647018 -264.010902)
		(mid 341.372819 -263.935067)
		(end 341.096346 -264.002266)
		(width 0.088646)
		(layer "In11.Cu")
		(net "M_D_CPU0_SA_CB<3>")
	)
	(arc
		(start 337.887564 -264.010902)
		(mid 337.604862 -263.935126)
		(end 337.32216 -264.010902)
		(width 0.088646)
		(layer "In11.Cu")
		(net "M_D_CPU0_SA_CB<3>")
	)
	(arc
		(start 337.32216 -264.010902)
		(mid 337.134962 -264.061045)
		(end 336.947764 -264.010902)
		(width 0.088646)
		(layer "In11.Cu")
		(net "M_D_CPU0_SA_CB<3>")
	)
	(arc
		(start 346.065094 -263.833102)
		(mid 345.971687 -263.896382)
		(end 345.87561 -263.95553)
		(width 0.088646)
		(layer "In11.Cu")
		(net "M_D_CPU0_SA_CB<3>")
	)
	(arc
		(start 336.947764 -264.010902)
		(mid 336.665062 -263.935126)
		(end 336.38236 -264.010902)
		(width 0.088646)
		(layer "In11.Cu")
		(net "M_D_CPU0_SA_CB<3>")
	)
	(arc
		(start 342.021414 -264.010902)
		(mid 341.834216 -264.061045)
		(end 341.647018 -264.010902)
		(width 0.088646)
		(layer "In11.Cu")
		(net "M_D_CPU0_SA_CB<3>")
	)
	(arc
		(start 334.128364 -264.010902)
		(mid 333.845662 -263.935126)
		(end 333.56296 -264.010902)
		(width 0.088646)
		(layer "In11.Cu")
		(net "M_D_CPU0_SA_CB<3>")
	)
	(segment
		(start 265.601958 -277.785576)
		(end 265.458194 -277.641812)
		(width 0.20066)
		(layer "F.Cu")
		(net "M_D_CPU0_SA_CB<2>")
	)
	(segment
		(start 261.327646 -278.066754)
		(end 260.180582 -278.066754)
		(width 0.20066)
		(layer "F.Cu")
		(net "M_D_CPU0_SA_CB<2>")
	)
	(segment
		(start 265.601958 -278.111204)
		(end 265.601958 -277.785576)
		(width 0.20066)
		(layer "F.Cu")
		(net "M_D_CPU0_SA_CB<2>")
	)
	(segment
		(start 262.50011 -277.631652)
		(end 261.762748 -277.631652)
		(width 0.20066)
		(layer "F.Cu")
		(net "M_D_CPU0_SA_CB<2>")
	)
	(segment
		(start 266.409678 -278.066754)
		(end 266.197842 -278.27859)
		(width 0.20066)
		(layer "F.Cu")
		(net "M_D_CPU0_SA_CB<2>")
	)
	(segment
		(start 267.724382 -278.066754)
		(end 266.409678 -278.066754)
		(width 0.20066)
		(layer "F.Cu")
		(net "M_D_CPU0_SA_CB<2>")
	)
	(segment
		(start 262.51027 -277.641812)
		(end 262.50011 -277.631652)
		(width 0.101854)
		(layer "F.Cu")
		(net "M_D_CPU0_SA_CB<2>")
	)
	(segment
		(start 347.942916 -263.96442)
		(end 347.942662 -263.964674)
		(width 0.20066)
		(layer "F.Cu")
		(net "M_D_CPU0_SA_CB<2>")
	)
	(segment
		(start 265.458194 -277.641812)
		(end 264.825226 -277.641812)
		(width 0.20066)
		(layer "F.Cu")
		(net "M_D_CPU0_SA_CB<2>")
	)
	(segment
		(start 261.762748 -277.631652)
		(end 261.327646 -278.066754)
		(width 0.20066)
		(layer "F.Cu")
		(net "M_D_CPU0_SA_CB<2>")
	)
	(segment
		(start 347.942662 -263.964674)
		(end 347.942662 -264.50036)
		(width 0.20066)
		(layer "F.Cu")
		(net "M_D_CPU0_SA_CB<2>")
	)
	(segment
		(start 266.197842 -278.27859)
		(end 265.769344 -278.27859)
		(width 0.20066)
		(layer "F.Cu")
		(net "M_D_CPU0_SA_CB<2>")
	)
	(segment
		(start 268.829282 -278.066754)
		(end 267.724382 -278.066754)
		(width 0.20066)
		(layer "F.Cu")
		(net "M_D_CPU0_SA_CB<2>")
	)
	(segment
		(start 265.769344 -278.27859)
		(end 265.601958 -278.111204)
		(width 0.20066)
		(layer "F.Cu")
		(net "M_D_CPU0_SA_CB<2>")
	)
	(segment
		(start 264.825226 -277.641812)
		(end 262.765286 -277.641812)
		(width 0.1016)
		(layer "F.Cu")
		(net "M_D_CPU0_SA_CB<2>")
	)
	(segment
		(start 262.765286 -277.641812)
		(end 262.51027 -277.641812)
		(width 0.101854)
		(layer "F.Cu")
		(net "M_D_CPU0_SA_CB<2>")
	)
	(segment
		(start 271.463008 -277.499826)
		(end 270.450056 -278.512778)
		(width 0.18288)
		(layer "In11.Cu")
		(net "M_D_CPU0_SA_CB<2>")
	)
	(segment
		(start 275.198078 -277.432262)
		(end 275.005038 -277.239222)
		(width 0.18288)
		(layer "In11.Cu")
		(net "M_D_CPU0_SA_CB<2>")
	)
	(segment
		(start 277.180294 -276.890226)
		(end 276.977094 -276.687026)
		(width 0.18288)
		(layer "In11.Cu")
		(net "M_D_CPU0_SA_CB<2>")
	)
	(segment
		(start 310.73471 -274.934426)
		(end 305.906424 -274.934426)
		(width 0.18288)
		(layer "In11.Cu")
		(net "M_D_CPU0_SA_CB<2>")
	)
	(segment
		(start 297.658536 -277.07336)
		(end 297.511978 -276.926802)
		(width 0.18288)
		(layer "In11.Cu")
		(net "M_D_CPU0_SA_CB<2>")
	)
	(segment
		(start 290.463478 -276.102826)
		(end 288.889694 -276.102826)
		(width 0.18288)
		(layer "In11.Cu")
		(net "M_D_CPU0_SA_CB<2>")
	)
	(segment
		(start 285.458154 -276.793452)
		(end 282.919678 -276.793452)
		(width 0.18288)
		(layer "In11.Cu")
		(net "M_D_CPU0_SA_CB<2>")
	)
	(segment
		(start 273.751294 -276.687026)
		(end 272.938494 -277.499826)
		(width 0.18288)
		(layer "In11.Cu")
		(net "M_D_CPU0_SA_CB<2>")
	)
	(segment
		(start 343.996264 -264.824718)
		(end 343.981532 -264.816082)
		(width 0.088646)
		(layer "In11.Cu")
		(net "M_D_CPU0_SA_CB<2>")
	)
	(segment
		(start 297.511978 -276.633686)
		(end 297.36542 -276.487128)
		(width 0.18288)
		(layer "In11.Cu")
		(net "M_D_CPU0_SA_CB<2>")
	)
	(segment
		(start 275.005038 -276.880066)
		(end 274.811998 -276.687026)
		(width 0.18288)
		(layer "In11.Cu")
		(net "M_D_CPU0_SA_CB<2>")
	)
	(segment
		(start 346.437712 -264.50036)
		(end 346.437712 -264.508996)
		(width 0.088646)
		(layer "In11.Cu")
		(net "M_D_CPU0_SA_CB<2>")
	)
	(segment
		(start 301.318422 -276.424644)
		(end 300.764194 -276.424644)
		(width 0.18288)
		(layer "In11.Cu")
		(net "M_D_CPU0_SA_CB<2>")
	)
	(segment
		(start 294.52824 -277.642066)
		(end 294.003476 -277.424642)
		(width 0.18288)
		(layer "In11.Cu")
		(net "M_D_CPU0_SA_CB<2>")
	)
	(segment
		(start 305.012344 -275.634958)
		(end 305.012344 -275.127466)
		(width 0.18288)
		(layer "In11.Cu")
		(net "M_D_CPU0_SA_CB<2>")
	)
	(segment
		(start 343.056464 -264.824718)
		(end 343.041732 -264.816082)
		(width 0.088646)
		(layer "In11.Cu")
		(net "M_D_CPU0_SA_CB<2>")
	)
	(segment
		(start 311.20715 -274.461986)
		(end 310.73471 -274.934426)
		(width 0.18288)
		(layer "In11.Cu")
		(net "M_D_CPU0_SA_CB<2>")
	)
	(segment
		(start 345.876118 -264.824718)
		(end 345.865704 -264.818622)
		(width 0.088646)
		(layer "In11.Cu")
		(net "M_D_CPU0_SA_CB<2>")
	)
	(segment
		(start 274.811998 -276.687026)
		(end 273.751294 -276.687026)
		(width 0.18288)
		(layer "In11.Cu")
		(net "M_D_CPU0_SA_CB<2>")
	)
	(segment
		(start 297.511978 -276.926802)
		(end 297.511978 -276.633686)
		(width 0.18288)
		(layer "In11.Cu")
		(net "M_D_CPU0_SA_CB<2>")
	)
	(segment
		(start 303.316894 -275.493226)
		(end 301.789846 -275.493226)
		(width 0.18288)
		(layer "In11.Cu")
		(net "M_D_CPU0_SA_CB<2>")
	)
	(segment
		(start 293.49446 -276.915626)
		(end 292.267894 -276.915626)
		(width 0.18288)
		(layer "In11.Cu")
		(net "M_D_CPU0_SA_CB<2>")
	)
	(segment
		(start 282.068524 -277.644606)
		(end 279.539446 -277.644606)
		(width 0.18288)
		(layer "In11.Cu")
		(net "M_D_CPU0_SA_CB<2>")
	)
	(segment
		(start 294.003476 -277.424642)
		(end 293.49446 -276.915626)
		(width 0.18288)
		(layer "In11.Cu")
		(net "M_D_CPU0_SA_CB<2>")
	)
	(segment
		(start 298.346876 -276.792944)
		(end 298.06646 -277.07336)
		(width 0.18288)
		(layer "In11.Cu")
		(net "M_D_CPU0_SA_CB<2>")
	)
	(segment
		(start 290.920678 -276.560026)
		(end 290.463478 -276.102826)
		(width 0.18288)
		(layer "In11.Cu")
		(net "M_D_CPU0_SA_CB<2>")
	)
	(segment
		(start 346.720414 -264.010902)
		(end 346.714318 -264.014458)
		(width 0.088646)
		(layer "In11.Cu")
		(net "M_D_CPU0_SA_CB<2>")
	)
	(segment
		(start 297.36542 -276.487128)
		(end 296.957496 -276.487128)
		(width 0.18288)
		(layer "In11.Cu")
		(net "M_D_CPU0_SA_CB<2>")
	)
	(segment
		(start 269.456154 -278.066754)
		(end 268.829282 -278.066754)
		(width 0.18288)
		(layer "In11.Cu")
		(net "M_D_CPU0_SA_CB<2>")
	)
	(segment
		(start 275.005038 -277.239222)
		(end 275.005038 -276.880066)
		(width 0.18288)
		(layer "In11.Cu")
		(net "M_D_CPU0_SA_CB<2>")
	)
	(segment
		(start 339.297518 -264.824718)
		(end 339.287104 -264.818622)
		(width 0.088646)
		(layer "In11.Cu")
		(net "M_D_CPU0_SA_CB<2>")
	)
	(segment
		(start 275.706078 -277.239222)
		(end 275.513038 -277.432262)
		(width 0.18288)
		(layer "In11.Cu")
		(net "M_D_CPU0_SA_CB<2>")
	)
	(segment
		(start 270.450056 -278.512778)
		(end 269.902178 -278.512778)
		(width 0.18288)
		(layer "In11.Cu")
		(net "M_D_CPU0_SA_CB<2>")
	)
	(segment
		(start 275.706078 -276.880066)
		(end 275.706078 -277.239222)
		(width 0.18288)
		(layer "In11.Cu")
		(net "M_D_CPU0_SA_CB<2>")
	)
	(segment
		(start 331.703426 -264.875264)
		(end 331.156056 -265.422634)
		(width 0.088646)
		(layer "In11.Cu")
		(net "M_D_CPU0_SA_CB<2>")
	)
	(segment
		(start 330.953872 -265.422634)
		(end 324.154038 -265.422634)
		(width 0.18288)
		(layer "In11.Cu")
		(net "M_D_CPU0_SA_CB<2>")
	)
	(segment
		(start 269.902178 -278.512778)
		(end 269.456154 -278.066754)
		(width 0.18288)
		(layer "In11.Cu")
		(net "M_D_CPU0_SA_CB<2>")
	)
	(segment
		(start 341.176864 -264.824718)
		(end 341.162132 -264.816082)
		(width 0.088646)
		(layer "In11.Cu")
		(net "M_D_CPU0_SA_CB<2>")
	)
	(segment
		(start 286.55518 -275.696426)
		(end 285.458154 -276.793452)
		(width 0.18288)
		(layer "In11.Cu")
		(net "M_D_CPU0_SA_CB<2>")
	)
	(segment
		(start 275.899118 -276.687026)
		(end 275.706078 -276.880066)
		(width 0.18288)
		(layer "In11.Cu")
		(net "M_D_CPU0_SA_CB<2>")
	)
	(segment
		(start 305.713384 -275.634958)
		(end 305.520344 -275.827998)
		(width 0.18288)
		(layer "In11.Cu")
		(net "M_D_CPU0_SA_CB<2>")
	)
	(segment
		(start 301.629826 -275.653246)
		(end 301.629826 -276.11324)
		(width 0.18288)
		(layer "In11.Cu")
		(net "M_D_CPU0_SA_CB<2>")
	)
	(segment
		(start 296.66438 -276.780244)
		(end 296.187876 -276.780244)
		(width 0.18288)
		(layer "In11.Cu")
		(net "M_D_CPU0_SA_CB<2>")
	)
	(segment
		(start 298.06646 -277.07336)
		(end 297.658536 -277.07336)
		(width 0.18288)
		(layer "In11.Cu")
		(net "M_D_CPU0_SA_CB<2>")
	)
	(segment
		(start 303.875694 -274.934426)
		(end 303.316894 -275.493226)
		(width 0.18288)
		(layer "In11.Cu")
		(net "M_D_CPU0_SA_CB<2>")
	)
	(segment
		(start 275.513038 -277.432262)
		(end 275.198078 -277.432262)
		(width 0.18288)
		(layer "In11.Cu")
		(net "M_D_CPU0_SA_CB<2>")
	)
	(segment
		(start 276.977094 -276.687026)
		(end 275.899118 -276.687026)
		(width 0.18288)
		(layer "In11.Cu")
		(net "M_D_CPU0_SA_CB<2>")
	)
	(segment
		(start 347.942662 -264.50036)
		(end 347.629988 -264.50036)
		(width 0.088646)
		(layer "In11.Cu")
		(net "M_D_CPU0_SA_CB<2>")
	)
	(segment
		(start 288.483294 -275.696426)
		(end 286.55518 -275.696426)
		(width 0.18288)
		(layer "In11.Cu")
		(net "M_D_CPU0_SA_CB<2>")
	)
	(segment
		(start 305.906424 -274.934426)
		(end 305.713384 -275.127466)
		(width 0.18288)
		(layer "In11.Cu")
		(net "M_D_CPU0_SA_CB<2>")
	)
	(segment
		(start 331.966062 -264.875264)
		(end 331.703426 -264.875264)
		(width 0.088646)
		(layer "In11.Cu")
		(net "M_D_CPU0_SA_CB<2>")
	)
	(segment
		(start 331.156056 -265.422634)
		(end 330.953872 -265.422634)
		(width 0.088646)
		(layer "In11.Cu")
		(net "M_D_CPU0_SA_CB<2>")
	)
	(segment
		(start 300.233588 -276.95525)
		(end 299.6311 -276.95525)
		(width 0.18288)
		(layer "In11.Cu")
		(net "M_D_CPU0_SA_CB<2>")
	)
	(segment
		(start 291.912294 -276.560026)
		(end 290.920678 -276.560026)
		(width 0.18288)
		(layer "In11.Cu")
		(net "M_D_CPU0_SA_CB<2>")
	)
	(segment
		(start 292.267894 -276.915626)
		(end 291.912294 -276.560026)
		(width 0.18288)
		(layer "In11.Cu")
		(net "M_D_CPU0_SA_CB<2>")
	)
	(segment
		(start 296.187876 -276.780244)
		(end 295.326054 -277.642066)
		(width 0.18288)
		(layer "In11.Cu")
		(net "M_D_CPU0_SA_CB<2>")
	)
	(segment
		(start 301.789846 -275.493226)
		(end 301.629826 -275.653246)
		(width 0.18288)
		(layer "In11.Cu")
		(net "M_D_CPU0_SA_CB<2>")
	)
	(segment
		(start 346.735146 -264.002266)
		(end 346.720414 -264.010902)
		(width 0.088646)
		(layer "In11.Cu")
		(net "M_D_CPU0_SA_CB<2>")
	)
	(segment
		(start 300.764194 -276.424644)
		(end 300.233588 -276.95525)
		(width 0.18288)
		(layer "In11.Cu")
		(net "M_D_CPU0_SA_CB<2>")
	)
	(segment
		(start 282.919678 -276.793452)
		(end 282.068524 -277.644606)
		(width 0.18288)
		(layer "In11.Cu")
		(net "M_D_CPU0_SA_CB<2>")
	)
	(segment
		(start 299.468794 -276.792944)
		(end 298.346876 -276.792944)
		(width 0.18288)
		(layer "In11.Cu")
		(net "M_D_CPU0_SA_CB<2>")
	)
	(segment
		(start 296.957496 -276.487128)
		(end 296.66438 -276.780244)
		(width 0.18288)
		(layer "In11.Cu")
		(net "M_D_CPU0_SA_CB<2>")
	)
	(segment
		(start 305.012344 -275.127466)
		(end 304.819304 -274.934426)
		(width 0.18288)
		(layer "In11.Cu")
		(net "M_D_CPU0_SA_CB<2>")
	)
	(segment
		(start 324.154038 -265.422634)
		(end 315.114686 -274.461986)
		(width 0.18288)
		(layer "In11.Cu")
		(net "M_D_CPU0_SA_CB<2>")
	)
	(segment
		(start 288.889694 -276.102826)
		(end 288.483294 -275.696426)
		(width 0.18288)
		(layer "In11.Cu")
		(net "M_D_CPU0_SA_CB<2>")
	)
	(segment
		(start 305.713384 -275.127466)
		(end 305.713384 -275.634958)
		(width 0.18288)
		(layer "In11.Cu")
		(net "M_D_CPU0_SA_CB<2>")
	)
	(segment
		(start 339.682328 -264.818622)
		(end 339.671914 -264.824718)
		(width 0.088646)
		(layer "In11.Cu")
		(net "M_D_CPU0_SA_CB<2>")
	)
	(segment
		(start 305.205384 -275.827998)
		(end 305.012344 -275.634958)
		(width 0.18288)
		(layer "In11.Cu")
		(net "M_D_CPU0_SA_CB<2>")
	)
	(segment
		(start 315.114686 -274.461986)
		(end 311.20715 -274.461986)
		(width 0.18288)
		(layer "In11.Cu")
		(net "M_D_CPU0_SA_CB<2>")
	)
	(segment
		(start 279.539446 -277.644606)
		(end 278.785066 -276.890226)
		(width 0.18288)
		(layer "In11.Cu")
		(net "M_D_CPU0_SA_CB<2>")
	)
	(segment
		(start 301.629826 -276.11324)
		(end 301.318422 -276.424644)
		(width 0.18288)
		(layer "In11.Cu")
		(net "M_D_CPU0_SA_CB<2>")
	)
	(segment
		(start 272.938494 -277.499826)
		(end 271.463008 -277.499826)
		(width 0.18288)
		(layer "In11.Cu")
		(net "M_D_CPU0_SA_CB<2>")
	)
	(segment
		(start 342.116664 -264.824718)
		(end 342.101932 -264.816082)
		(width 0.088646)
		(layer "In11.Cu")
		(net "M_D_CPU0_SA_CB<2>")
	)
	(segment
		(start 295.326054 -277.642066)
		(end 294.52824 -277.642066)
		(width 0.18288)
		(layer "In11.Cu")
		(net "M_D_CPU0_SA_CB<2>")
	)
	(segment
		(start 305.520344 -275.827998)
		(end 305.205384 -275.827998)
		(width 0.18288)
		(layer "In11.Cu")
		(net "M_D_CPU0_SA_CB<2>")
	)
	(segment
		(start 347.629988 -264.50036)
		(end 347.564456 -264.434828)
		(width 0.088646)
		(layer "In11.Cu")
		(net "M_D_CPU0_SA_CB<2>")
	)
	(segment
		(start 299.6311 -276.95525)
		(end 299.468794 -276.792944)
		(width 0.18288)
		(layer "In11.Cu")
		(net "M_D_CPU0_SA_CB<2>")
	)
	(segment
		(start 278.785066 -276.890226)
		(end 277.180294 -276.890226)
		(width 0.18288)
		(layer "In11.Cu")
		(net "M_D_CPU0_SA_CB<2>")
	)
	(segment
		(start 344.936064 -264.824718)
		(end 344.921332 -264.816082)
		(width 0.088646)
		(layer "In11.Cu")
		(net "M_D_CPU0_SA_CB<2>")
	)
	(segment
		(start 304.819304 -274.934426)
		(end 303.875694 -274.934426)
		(width 0.18288)
		(layer "In11.Cu")
		(net "M_D_CPU0_SA_CB<2>")
	)
	(arc
		(start 332.718664 -264.824718)
		(mid 332.435962 -264.748942)
		(end 332.15326 -264.824718)
		(width 0.088646)
		(layer "In11.Cu")
		(net "M_D_CPU0_SA_CB<2>")
	)
	(arc
		(start 342.101932 -264.816082)
		(mid 341.825457 -264.748762)
		(end 341.55126 -264.824718)
		(width 0.088646)
		(layer "In11.Cu")
		(net "M_D_CPU0_SA_CB<2>")
	)
	(arc
		(start 344.921332 -264.816082)
		(mid 344.644857 -264.748762)
		(end 344.37066 -264.824718)
		(width 0.088646)
		(layer "In11.Cu")
		(net "M_D_CPU0_SA_CB<2>")
	)
	(arc
		(start 333.658464 -264.824718)
		(mid 333.375762 -264.748942)
		(end 333.09306 -264.824718)
		(width 0.088646)
		(layer "In11.Cu")
		(net "M_D_CPU0_SA_CB<2>")
	)
	(arc
		(start 332.15326 -264.824718)
		(mid 332.062988 -264.862317)
		(end 331.966062 -264.875264)
		(width 0.088646)
		(layer "In11.Cu")
		(net "M_D_CPU0_SA_CB<2>")
	)
	(arc
		(start 340.61146 -264.824718)
		(mid 340.424262 -264.874861)
		(end 340.237064 -264.824718)
		(width 0.088646)
		(layer "In11.Cu")
		(net "M_D_CPU0_SA_CB<2>")
	)
	(arc
		(start 339.671914 -264.824718)
		(mid 339.484716 -264.874861)
		(end 339.297518 -264.824718)
		(width 0.088646)
		(layer "In11.Cu")
		(net "M_D_CPU0_SA_CB<2>")
	)
	(arc
		(start 342.49106 -264.824718)
		(mid 342.303862 -264.874861)
		(end 342.116664 -264.824718)
		(width 0.088646)
		(layer "In11.Cu")
		(net "M_D_CPU0_SA_CB<2>")
	)
	(arc
		(start 346.250514 -264.824718)
		(mid 346.063316 -264.874861)
		(end 345.876118 -264.824718)
		(width 0.088646)
		(layer "In11.Cu")
		(net "M_D_CPU0_SA_CB<2>")
	)
	(arc
		(start 335.91246 -264.824718)
		(mid 335.725262 -264.874861)
		(end 335.538064 -264.824718)
		(width 0.088646)
		(layer "In11.Cu")
		(net "M_D_CPU0_SA_CB<2>")
	)
	(arc
		(start 345.31046 -264.824718)
		(mid 345.123262 -264.874861)
		(end 344.936064 -264.824718)
		(width 0.088646)
		(layer "In11.Cu")
		(net "M_D_CPU0_SA_CB<2>")
	)
	(arc
		(start 340.237064 -264.824718)
		(mid 339.960505 -264.748975)
		(end 339.682328 -264.818622)
		(width 0.088646)
		(layer "In11.Cu")
		(net "M_D_CPU0_SA_CB<2>")
	)
	(arc
		(start 336.85226 -264.824718)
		(mid 336.665062 -264.874861)
		(end 336.477864 -264.824718)
		(width 0.088646)
		(layer "In11.Cu")
		(net "M_D_CPU0_SA_CB<2>")
	)
	(arc
		(start 338.73186 -264.824718)
		(mid 338.544662 -264.874861)
		(end 338.357464 -264.824718)
		(width 0.088646)
		(layer "In11.Cu")
		(net "M_D_CPU0_SA_CB<2>")
	)
	(arc
		(start 334.598264 -264.824718)
		(mid 334.315562 -264.748942)
		(end 334.03286 -264.824718)
		(width 0.088646)
		(layer "In11.Cu")
		(net "M_D_CPU0_SA_CB<2>")
	)
	(arc
		(start 337.79206 -264.824718)
		(mid 337.604862 -264.874861)
		(end 337.417664 -264.824718)
		(width 0.088646)
		(layer "In11.Cu")
		(net "M_D_CPU0_SA_CB<2>")
	)
	(arc
		(start 334.03286 -264.824718)
		(mid 333.845662 -264.874861)
		(end 333.658464 -264.824718)
		(width 0.088646)
		(layer "In11.Cu")
		(net "M_D_CPU0_SA_CB<2>")
	)
	(arc
		(start 346.714318 -264.014458)
		(mid 346.511731 -264.220809)
		(end 346.437712 -264.50036)
		(width 0.088646)
		(layer "In11.Cu")
		(net "M_D_CPU0_SA_CB<2>")
	)
	(arc
		(start 344.37066 -264.824718)
		(mid 344.183462 -264.874861)
		(end 343.996264 -264.824718)
		(width 0.088646)
		(layer "In11.Cu")
		(net "M_D_CPU0_SA_CB<2>")
	)
	(arc
		(start 345.865704 -264.818622)
		(mid 345.587272 -264.748776)
		(end 345.31046 -264.824718)
		(width 0.088646)
		(layer "In11.Cu")
		(net "M_D_CPU0_SA_CB<2>")
	)
	(arc
		(start 335.538064 -264.824718)
		(mid 335.255362 -264.748942)
		(end 334.97266 -264.824718)
		(width 0.088646)
		(layer "In11.Cu")
		(net "M_D_CPU0_SA_CB<2>")
	)
	(arc
		(start 338.357464 -264.824718)
		(mid 338.074762 -264.748942)
		(end 337.79206 -264.824718)
		(width 0.088646)
		(layer "In11.Cu")
		(net "M_D_CPU0_SA_CB<2>")
	)
	(arc
		(start 347.564456 -264.434828)
		(mid 347.475368 -264.189843)
		(end 347.285818 -264.010902)
		(width 0.088646)
		(layer "In11.Cu")
		(net "M_D_CPU0_SA_CB<2>")
	)
	(arc
		(start 339.287104 -264.818622)
		(mid 339.008672 -264.748776)
		(end 338.73186 -264.824718)
		(width 0.088646)
		(layer "In11.Cu")
		(net "M_D_CPU0_SA_CB<2>")
	)
	(arc
		(start 336.477864 -264.824718)
		(mid 336.195162 -264.748942)
		(end 335.91246 -264.824718)
		(width 0.088646)
		(layer "In11.Cu")
		(net "M_D_CPU0_SA_CB<2>")
	)
	(arc
		(start 346.437712 -264.508996)
		(mid 346.385442 -264.691361)
		(end 346.250514 -264.824718)
		(width 0.088646)
		(layer "In11.Cu")
		(net "M_D_CPU0_SA_CB<2>")
	)
	(arc
		(start 343.43086 -264.824718)
		(mid 343.243662 -264.874861)
		(end 343.056464 -264.824718)
		(width 0.088646)
		(layer "In11.Cu")
		(net "M_D_CPU0_SA_CB<2>")
	)
	(arc
		(start 334.97266 -264.824718)
		(mid 334.785462 -264.874861)
		(end 334.598264 -264.824718)
		(width 0.088646)
		(layer "In11.Cu")
		(net "M_D_CPU0_SA_CB<2>")
	)
	(arc
		(start 341.162132 -264.816082)
		(mid 340.885657 -264.748762)
		(end 340.61146 -264.824718)
		(width 0.088646)
		(layer "In11.Cu")
		(net "M_D_CPU0_SA_CB<2>")
	)
	(arc
		(start 343.041732 -264.816082)
		(mid 342.765257 -264.748762)
		(end 342.49106 -264.824718)
		(width 0.088646)
		(layer "In11.Cu")
		(net "M_D_CPU0_SA_CB<2>")
	)
	(arc
		(start 341.55126 -264.824718)
		(mid 341.364062 -264.874861)
		(end 341.176864 -264.824718)
		(width 0.088646)
		(layer "In11.Cu")
		(net "M_D_CPU0_SA_CB<2>")
	)
	(arc
		(start 347.285818 -264.010902)
		(mid 347.011619 -263.935067)
		(end 346.735146 -264.002266)
		(width 0.088646)
		(layer "In11.Cu")
		(net "M_D_CPU0_SA_CB<2>")
	)
	(arc
		(start 333.09306 -264.824718)
		(mid 332.905862 -264.874861)
		(end 332.718664 -264.824718)
		(width 0.088646)
		(layer "In11.Cu")
		(net "M_D_CPU0_SA_CB<2>")
	)
	(arc
		(start 343.981532 -264.816082)
		(mid 343.705057 -264.748762)
		(end 343.43086 -264.824718)
		(width 0.088646)
		(layer "In11.Cu")
		(net "M_D_CPU0_SA_CB<2>")
	)
	(arc
		(start 337.417664 -264.824718)
		(mid 337.134962 -264.748942)
		(end 336.85226 -264.824718)
		(width 0.088646)
		(layer "In11.Cu")
		(net "M_D_CPU0_SA_CB<2>")
	)
	(segment
		(start 257.414776 -277.216616)
		(end 256.080514 -277.216616)
		(width 0.20066)
		(layer "F.Cu")
		(net "M_D_CPU0_SA_CB<1>")
	)
	(segment
		(start 261.050786 -276.791674)
		(end 259.065268 -276.791674)
		(width 0.1016)
		(layer "F.Cu")
		(net "M_D_CPU0_SA_CB<1>")
	)
	(segment
		(start 261.381494 -276.791674)
		(end 261.050786 -276.791674)
		(width 0.101854)
		(layer "F.Cu")
		(net "M_D_CPU0_SA_CB<1>")
	)
	(segment
		(start 261.984998 -277.216616)
		(end 261.560056 -276.791674)
		(width 0.20066)
		(layer "F.Cu")
		(net "M_D_CPU0_SA_CB<1>")
	)
	(segment
		(start 264.729214 -277.216616)
		(end 263.624314 -277.216616)
		(width 0.20066)
		(layer "F.Cu")
		(net "M_D_CPU0_SA_CB<1>")
	)
	(segment
		(start 346.532962 -263.150604)
		(end 346.532962 -263.68629)
		(width 0.20066)
		(layer "F.Cu")
		(net "M_D_CPU0_SA_CB<1>")
	)
	(segment
		(start 261.560056 -276.791674)
		(end 261.381494 -276.791674)
		(width 0.20066)
		(layer "F.Cu")
		(net "M_D_CPU0_SA_CB<1>")
	)
	(segment
		(start 258.130548 -277.427944)
		(end 257.626104 -277.427944)
		(width 0.20066)
		(layer "F.Cu")
		(net "M_D_CPU0_SA_CB<1>")
	)
	(segment
		(start 258.44754 -276.782784)
		(end 258.28498 -276.945344)
		(width 0.20066)
		(layer "F.Cu")
		(net "M_D_CPU0_SA_CB<1>")
	)
	(segment
		(start 258.28498 -277.273512)
		(end 258.130548 -277.427944)
		(width 0.20066)
		(layer "F.Cu")
		(net "M_D_CPU0_SA_CB<1>")
	)
	(segment
		(start 259.065268 -276.791674)
		(end 259.056378 -276.782784)
		(width 0.1016)
		(layer "F.Cu")
		(net "M_D_CPU0_SA_CB<1>")
	)
	(segment
		(start 346.532962 -263.68629)
		(end 346.533216 -263.686544)
		(width 0.20066)
		(layer "F.Cu")
		(net "M_D_CPU0_SA_CB<1>")
	)
	(segment
		(start 257.626104 -277.427944)
		(end 257.414776 -277.216616)
		(width 0.20066)
		(layer "F.Cu")
		(net "M_D_CPU0_SA_CB<1>")
	)
	(segment
		(start 263.624314 -277.216616)
		(end 261.984998 -277.216616)
		(width 0.20066)
		(layer "F.Cu")
		(net "M_D_CPU0_SA_CB<1>")
	)
	(segment
		(start 258.28498 -276.945344)
		(end 258.28498 -277.273512)
		(width 0.20066)
		(layer "F.Cu")
		(net "M_D_CPU0_SA_CB<1>")
	)
	(segment
		(start 259.056378 -276.782784)
		(end 258.44754 -276.782784)
		(width 0.20066)
		(layer "F.Cu")
		(net "M_D_CPU0_SA_CB<1>")
	)
	(segment
		(start 341.176864 -264.176002)
		(end 341.162132 -264.184638)
		(width 0.088646)
		(layer "In11.Cu")
		(net "M_D_CPU0_SA_CB<1>")
	)
	(segment
		(start 331.875638 -264.125456)
		(end 331.346556 -264.654538)
		(width 0.088646)
		(layer "In11.Cu")
		(net "M_D_CPU0_SA_CB<1>")
	)
	(segment
		(start 294.2209 -276.791928)
		(end 293.291514 -275.862542)
		(width 0.18288)
		(layer "In11.Cu")
		(net "M_D_CPU0_SA_CB<1>")
	)
	(segment
		(start 265.153902 -277.641304)
		(end 264.729214 -277.216616)
		(width 0.18288)
		(layer "In11.Cu")
		(net "M_D_CPU0_SA_CB<1>")
	)
	(segment
		(start 314.89777 -273.943826)
		(end 310.918098 -273.943826)
		(width 0.18288)
		(layer "In11.Cu")
		(net "M_D_CPU0_SA_CB<1>")
	)
	(segment
		(start 266.011152 -278.124412)
		(end 266.011152 -277.834344)
		(width 0.18288)
		(layer "In11.Cu")
		(net "M_D_CPU0_SA_CB<1>")
	)
	(segment
		(start 300.606714 -275.780754)
		(end 299.654976 -275.780754)
		(width 0.18288)
		(layer "In11.Cu")
		(net "M_D_CPU0_SA_CB<1>")
	)
	(segment
		(start 271.312894 -276.915626)
		(end 270.779494 -277.449026)
		(width 0.18288)
		(layer "In11.Cu")
		(net "M_D_CPU0_SA_CB<1>")
	)
	(segment
		(start 277.180294 -276.102826)
		(end 273.548094 -276.102826)
		(width 0.18288)
		(layer "In11.Cu")
		(net "M_D_CPU0_SA_CB<1>")
	)
	(segment
		(start 266.712192 -278.124412)
		(end 266.519152 -278.317452)
		(width 0.18288)
		(layer "In11.Cu")
		(net "M_D_CPU0_SA_CB<1>")
	)
	(segment
		(start 343.996264 -264.176002)
		(end 343.981532 -264.184638)
		(width 0.088646)
		(layer "In11.Cu")
		(net "M_D_CPU0_SA_CB<1>")
	)
	(segment
		(start 265.818112 -277.641304)
		(end 265.153902 -277.641304)
		(width 0.18288)
		(layer "In11.Cu")
		(net "M_D_CPU0_SA_CB<1>")
	)
	(segment
		(start 284.795722 -275.67509)
		(end 284.530546 -275.940266)
		(width 0.18288)
		(layer "In11.Cu")
		(net "M_D_CPU0_SA_CB<1>")
	)
	(segment
		(start 266.712192 -277.834344)
		(end 266.712192 -278.124412)
		(width 0.18288)
		(layer "In11.Cu")
		(net "M_D_CPU0_SA_CB<1>")
	)
	(segment
		(start 287.28035 -274.924012)
		(end 286.466534 -274.924012)
		(width 0.18288)
		(layer "In11.Cu")
		(net "M_D_CPU0_SA_CB<1>")
	)
	(segment
		(start 287.97377 -275.118068)
		(end 287.474406 -275.118068)
		(width 0.18288)
		(layer "In11.Cu")
		(net "M_D_CPU0_SA_CB<1>")
	)
	(segment
		(start 291.138356 -276.012656)
		(end 290.049712 -274.924012)
		(width 0.18288)
		(layer "In11.Cu")
		(net "M_D_CPU0_SA_CB<1>")
	)
	(segment
		(start 278.567896 -275.823426)
		(end 277.459694 -275.823426)
		(width 0.18288)
		(layer "In11.Cu")
		(net "M_D_CPU0_SA_CB<1>")
	)
	(segment
		(start 331.966062 -264.125456)
		(end 331.875638 -264.125456)
		(width 0.088646)
		(layer "In11.Cu")
		(net "M_D_CPU0_SA_CB<1>")
	)
	(segment
		(start 340.237064 -264.176002)
		(end 340.22665 -264.182098)
		(width 0.088646)
		(layer "In11.Cu")
		(net "M_D_CPU0_SA_CB<1>")
	)
	(segment
		(start 344.936064 -264.176002)
		(end 344.921332 -264.184638)
		(width 0.088646)
		(layer "In11.Cu")
		(net "M_D_CPU0_SA_CB<1>")
	)
	(segment
		(start 269.370302 -277.449026)
		(end 269.178024 -277.641304)
		(width 0.18288)
		(layer "In11.Cu")
		(net "M_D_CPU0_SA_CB<1>")
	)
	(segment
		(start 342.116664 -264.176002)
		(end 342.101932 -264.184638)
		(width 0.088646)
		(layer "In11.Cu")
		(net "M_D_CPU0_SA_CB<1>")
	)
	(segment
		(start 301.427642 -274.959826)
		(end 300.606714 -275.780754)
		(width 0.18288)
		(layer "In11.Cu")
		(net "M_D_CPU0_SA_CB<1>")
	)
	(segment
		(start 330.953872 -264.914634)
		(end 323.926962 -264.914634)
		(width 0.18288)
		(layer "In11.Cu")
		(net "M_D_CPU0_SA_CB<1>")
	)
	(segment
		(start 284.530546 -275.940266)
		(end 282.92298 -275.940266)
		(width 0.18288)
		(layer "In11.Cu")
		(net "M_D_CPU0_SA_CB<1>")
	)
	(segment
		(start 282.074874 -276.788372)
		(end 279.532842 -276.788372)
		(width 0.18288)
		(layer "In11.Cu")
		(net "M_D_CPU0_SA_CB<1>")
	)
	(segment
		(start 282.92298 -275.940266)
		(end 282.074874 -276.788372)
		(width 0.18288)
		(layer "In11.Cu")
		(net "M_D_CPU0_SA_CB<1>")
	)
	(segment
		(start 296.236898 -275.943314)
		(end 295.388284 -276.791928)
		(width 0.18288)
		(layer "In11.Cu")
		(net "M_D_CPU0_SA_CB<1>")
	)
	(segment
		(start 331.25791 -264.914634)
		(end 330.953872 -264.914634)
		(width 0.088646)
		(layer "In11.Cu")
		(net "M_D_CPU0_SA_CB<1>")
	)
	(segment
		(start 295.388284 -276.791928)
		(end 294.2209 -276.791928)
		(width 0.18288)
		(layer "In11.Cu")
		(net "M_D_CPU0_SA_CB<1>")
	)
	(segment
		(start 331.346556 -264.654538)
		(end 331.346556 -264.825988)
		(width 0.088646)
		(layer "In11.Cu")
		(net "M_D_CPU0_SA_CB<1>")
	)
	(segment
		(start 331.346556 -264.825988)
		(end 331.25791 -264.914634)
		(width 0.088646)
		(layer "In11.Cu")
		(net "M_D_CPU0_SA_CB<1>")
	)
	(segment
		(start 286.466534 -274.924012)
		(end 285.715456 -275.67509)
		(width 0.18288)
		(layer "In11.Cu")
		(net "M_D_CPU0_SA_CB<1>")
	)
	(segment
		(start 293.291514 -275.862542)
		(end 292.254178 -275.862542)
		(width 0.18288)
		(layer "In11.Cu")
		(net "M_D_CPU0_SA_CB<1>")
	)
	(segment
		(start 269.178024 -277.641304)
		(end 266.905232 -277.641304)
		(width 0.18288)
		(layer "In11.Cu")
		(net "M_D_CPU0_SA_CB<1>")
	)
	(segment
		(start 310.491124 -274.3708)
		(end 303.67732 -274.3708)
		(width 0.18288)
		(layer "In11.Cu")
		(net "M_D_CPU0_SA_CB<1>")
	)
	(segment
		(start 292.254178 -275.862542)
		(end 292.104064 -276.012656)
		(width 0.18288)
		(layer "In11.Cu")
		(net "M_D_CPU0_SA_CB<1>")
	)
	(segment
		(start 285.715456 -275.67509)
		(end 284.795722 -275.67509)
		(width 0.18288)
		(layer "In11.Cu")
		(net "M_D_CPU0_SA_CB<1>")
	)
	(segment
		(start 266.011152 -277.834344)
		(end 265.818112 -277.641304)
		(width 0.18288)
		(layer "In11.Cu")
		(net "M_D_CPU0_SA_CB<1>")
	)
	(segment
		(start 323.926962 -264.914634)
		(end 314.89777 -273.943826)
		(width 0.18288)
		(layer "In11.Cu")
		(net "M_D_CPU0_SA_CB<1>")
	)
	(segment
		(start 272.735294 -276.915626)
		(end 271.312894 -276.915626)
		(width 0.18288)
		(layer "In11.Cu")
		(net "M_D_CPU0_SA_CB<1>")
	)
	(segment
		(start 266.204192 -278.317452)
		(end 266.011152 -278.124412)
		(width 0.18288)
		(layer "In11.Cu")
		(net "M_D_CPU0_SA_CB<1>")
	)
	(segment
		(start 292.104064 -276.012656)
		(end 291.138356 -276.012656)
		(width 0.18288)
		(layer "In11.Cu")
		(net "M_D_CPU0_SA_CB<1>")
	)
	(segment
		(start 303.088294 -274.959826)
		(end 301.427642 -274.959826)
		(width 0.18288)
		(layer "In11.Cu")
		(net "M_D_CPU0_SA_CB<1>")
	)
	(segment
		(start 339.297518 -264.176002)
		(end 339.287104 -264.182098)
		(width 0.088646)
		(layer "In11.Cu")
		(net "M_D_CPU0_SA_CB<1>")
	)
	(segment
		(start 273.548094 -276.102826)
		(end 272.735294 -276.915626)
		(width 0.18288)
		(layer "In11.Cu")
		(net "M_D_CPU0_SA_CB<1>")
	)
	(segment
		(start 310.918098 -273.943826)
		(end 310.491124 -274.3708)
		(width 0.18288)
		(layer "In11.Cu")
		(net "M_D_CPU0_SA_CB<1>")
	)
	(segment
		(start 279.532842 -276.788372)
		(end 278.567896 -275.823426)
		(width 0.18288)
		(layer "In11.Cu")
		(net "M_D_CPU0_SA_CB<1>")
	)
	(segment
		(start 299.492416 -275.943314)
		(end 296.236898 -275.943314)
		(width 0.18288)
		(layer "In11.Cu")
		(net "M_D_CPU0_SA_CB<1>")
	)
	(segment
		(start 270.779494 -277.449026)
		(end 269.370302 -277.449026)
		(width 0.18288)
		(layer "In11.Cu")
		(net "M_D_CPU0_SA_CB<1>")
	)
	(segment
		(start 266.905232 -277.641304)
		(end 266.712192 -277.834344)
		(width 0.18288)
		(layer "In11.Cu")
		(net "M_D_CPU0_SA_CB<1>")
	)
	(segment
		(start 290.049712 -274.924012)
		(end 288.167826 -274.924012)
		(width 0.18288)
		(layer "In11.Cu")
		(net "M_D_CPU0_SA_CB<1>")
	)
	(segment
		(start 299.654976 -275.780754)
		(end 299.492416 -275.943314)
		(width 0.18288)
		(layer "In11.Cu")
		(net "M_D_CPU0_SA_CB<1>")
	)
	(segment
		(start 288.167826 -274.924012)
		(end 287.97377 -275.118068)
		(width 0.18288)
		(layer "In11.Cu")
		(net "M_D_CPU0_SA_CB<1>")
	)
	(segment
		(start 287.474406 -275.118068)
		(end 287.28035 -274.924012)
		(width 0.18288)
		(layer "In11.Cu")
		(net "M_D_CPU0_SA_CB<1>")
	)
	(segment
		(start 303.67732 -274.3708)
		(end 303.088294 -274.959826)
		(width 0.18288)
		(layer "In11.Cu")
		(net "M_D_CPU0_SA_CB<1>")
	)
	(segment
		(start 266.519152 -278.317452)
		(end 266.204192 -278.317452)
		(width 0.18288)
		(layer "In11.Cu")
		(net "M_D_CPU0_SA_CB<1>")
	)
	(segment
		(start 345.971876 -264.119868)
		(end 345.865704 -264.182098)
		(width 0.088646)
		(layer "In11.Cu")
		(net "M_D_CPU0_SA_CB<1>")
	)
	(segment
		(start 277.459694 -275.823426)
		(end 277.180294 -276.102826)
		(width 0.18288)
		(layer "In11.Cu")
		(net "M_D_CPU0_SA_CB<1>")
	)
	(arc
		(start 346.533216 -263.686544)
		(mid 346.360637 -263.845088)
		(end 346.17533 -263.98855)
		(width 0.088646)
		(layer "In11.Cu")
		(net "M_D_CPU0_SA_CB<1>")
	)
	(arc
		(start 338.73186 -264.176002)
		(mid 338.544662 -264.125859)
		(end 338.357464 -264.176002)
		(width 0.088646)
		(layer "In11.Cu")
		(net "M_D_CPU0_SA_CB<1>")
	)
	(arc
		(start 340.22665 -264.182098)
		(mid 339.948472 -264.251821)
		(end 339.671914 -264.176002)
		(width 0.088646)
		(layer "In11.Cu")
		(net "M_D_CPU0_SA_CB<1>")
	)
	(arc
		(start 339.671914 -264.176002)
		(mid 339.484716 -264.125859)
		(end 339.297518 -264.176002)
		(width 0.088646)
		(layer "In11.Cu")
		(net "M_D_CPU0_SA_CB<1>")
	)
	(arc
		(start 337.417664 -264.176002)
		(mid 337.134962 -264.251778)
		(end 336.85226 -264.176002)
		(width 0.088646)
		(layer "In11.Cu")
		(net "M_D_CPU0_SA_CB<1>")
	)
	(arc
		(start 340.61146 -264.176002)
		(mid 340.424262 -264.125859)
		(end 340.237064 -264.176002)
		(width 0.088646)
		(layer "In11.Cu")
		(net "M_D_CPU0_SA_CB<1>")
	)
	(arc
		(start 334.598264 -264.176002)
		(mid 334.315562 -264.251778)
		(end 334.03286 -264.176002)
		(width 0.088646)
		(layer "In11.Cu")
		(net "M_D_CPU0_SA_CB<1>")
	)
	(arc
		(start 335.91246 -264.176002)
		(mid 335.725262 -264.125859)
		(end 335.538064 -264.176002)
		(width 0.088646)
		(layer "In11.Cu")
		(net "M_D_CPU0_SA_CB<1>")
	)
	(arc
		(start 341.55126 -264.176002)
		(mid 341.364062 -264.125859)
		(end 341.176864 -264.176002)
		(width 0.088646)
		(layer "In11.Cu")
		(net "M_D_CPU0_SA_CB<1>")
	)
	(arc
		(start 334.03286 -264.176002)
		(mid 333.845662 -264.125859)
		(end 333.658464 -264.176002)
		(width 0.088646)
		(layer "In11.Cu")
		(net "M_D_CPU0_SA_CB<1>")
	)
	(arc
		(start 345.31046 -264.176002)
		(mid 345.123262 -264.125859)
		(end 344.936064 -264.176002)
		(width 0.088646)
		(layer "In11.Cu")
		(net "M_D_CPU0_SA_CB<1>")
	)
	(arc
		(start 344.37066 -264.176002)
		(mid 344.183462 -264.125859)
		(end 343.996264 -264.176002)
		(width 0.088646)
		(layer "In11.Cu")
		(net "M_D_CPU0_SA_CB<1>")
	)
	(arc
		(start 339.287104 -264.182098)
		(mid 339.008672 -264.251944)
		(end 338.73186 -264.176002)
		(width 0.088646)
		(layer "In11.Cu")
		(net "M_D_CPU0_SA_CB<1>")
	)
	(arc
		(start 344.921332 -264.184638)
		(mid 344.644857 -264.251958)
		(end 344.37066 -264.176002)
		(width 0.088646)
		(layer "In11.Cu")
		(net "M_D_CPU0_SA_CB<1>")
	)
	(arc
		(start 342.49106 -264.176002)
		(mid 342.303862 -264.125859)
		(end 342.116664 -264.176002)
		(width 0.088646)
		(layer "In11.Cu")
		(net "M_D_CPU0_SA_CB<1>")
	)
	(arc
		(start 341.162132 -264.184638)
		(mid 340.885657 -264.251958)
		(end 340.61146 -264.176002)
		(width 0.088646)
		(layer "In11.Cu")
		(net "M_D_CPU0_SA_CB<1>")
	)
	(arc
		(start 343.056464 -264.176002)
		(mid 342.773762 -264.251778)
		(end 342.49106 -264.176002)
		(width 0.088646)
		(layer "In11.Cu")
		(net "M_D_CPU0_SA_CB<1>")
	)
	(arc
		(start 335.538064 -264.176002)
		(mid 335.255362 -264.251778)
		(end 334.97266 -264.176002)
		(width 0.088646)
		(layer "In11.Cu")
		(net "M_D_CPU0_SA_CB<1>")
	)
	(arc
		(start 343.981532 -264.184638)
		(mid 343.705057 -264.251958)
		(end 343.43086 -264.176002)
		(width 0.088646)
		(layer "In11.Cu")
		(net "M_D_CPU0_SA_CB<1>")
	)
	(arc
		(start 333.658464 -264.176002)
		(mid 333.375762 -264.251778)
		(end 333.09306 -264.176002)
		(width 0.088646)
		(layer "In11.Cu")
		(net "M_D_CPU0_SA_CB<1>")
	)
	(arc
		(start 338.357464 -264.176002)
		(mid 338.074762 -264.251778)
		(end 337.79206 -264.176002)
		(width 0.088646)
		(layer "In11.Cu")
		(net "M_D_CPU0_SA_CB<1>")
	)
	(arc
		(start 332.15326 -264.176002)
		(mid 332.062988 -264.138403)
		(end 331.966062 -264.125456)
		(width 0.088646)
		(layer "In11.Cu")
		(net "M_D_CPU0_SA_CB<1>")
	)
	(arc
		(start 345.865704 -264.182098)
		(mid 345.587272 -264.251944)
		(end 345.31046 -264.176002)
		(width 0.088646)
		(layer "In11.Cu")
		(net "M_D_CPU0_SA_CB<1>")
	)
	(arc
		(start 332.718664 -264.176002)
		(mid 332.435962 -264.251778)
		(end 332.15326 -264.176002)
		(width 0.088646)
		(layer "In11.Cu")
		(net "M_D_CPU0_SA_CB<1>")
	)
	(arc
		(start 342.101932 -264.184638)
		(mid 341.825457 -264.251958)
		(end 341.55126 -264.176002)
		(width 0.088646)
		(layer "In11.Cu")
		(net "M_D_CPU0_SA_CB<1>")
	)
	(arc
		(start 336.477864 -264.176002)
		(mid 336.195162 -264.251778)
		(end 335.91246 -264.176002)
		(width 0.088646)
		(layer "In11.Cu")
		(net "M_D_CPU0_SA_CB<1>")
	)
	(arc
		(start 333.09306 -264.176002)
		(mid 332.905862 -264.125859)
		(end 332.718664 -264.176002)
		(width 0.088646)
		(layer "In11.Cu")
		(net "M_D_CPU0_SA_CB<1>")
	)
	(arc
		(start 334.97266 -264.176002)
		(mid 334.785462 -264.125859)
		(end 334.598264 -264.176002)
		(width 0.088646)
		(layer "In11.Cu")
		(net "M_D_CPU0_SA_CB<1>")
	)
	(arc
		(start 346.17533 -263.98855)
		(mid 346.075034 -264.056426)
		(end 345.971876 -264.119868)
		(width 0.088646)
		(layer "In11.Cu")
		(net "M_D_CPU0_SA_CB<1>")
	)
	(arc
		(start 337.79206 -264.176002)
		(mid 337.604862 -264.125859)
		(end 337.417664 -264.176002)
		(width 0.088646)
		(layer "In11.Cu")
		(net "M_D_CPU0_SA_CB<1>")
	)
	(arc
		(start 336.85226 -264.176002)
		(mid 336.665062 -264.125859)
		(end 336.477864 -264.176002)
		(width 0.088646)
		(layer "In11.Cu")
		(net "M_D_CPU0_SA_CB<1>")
	)
	(arc
		(start 343.43086 -264.176002)
		(mid 343.243662 -264.125859)
		(end 343.056464 -264.176002)
		(width 0.088646)
		(layer "In11.Cu")
		(net "M_D_CPU0_SA_CB<1>")
	)
	(segment
		(start 259.056378 -278.483568)
		(end 258.49453 -278.483568)
		(width 0.20066)
		(layer "F.Cu")
		(net "M_D_CPU0_SA_CB<0>")
	)
	(segment
		(start 258.28498 -278.982678)
		(end 258.11226 -279.155398)
		(width 0.20066)
		(layer "F.Cu")
		(net "M_D_CPU0_SA_CB<0>")
	)
	(segment
		(start 261.381494 -278.491696)
		(end 259.31241 -278.491696)
		(width 0.1016)
		(layer "F.Cu")
		(net "M_D_CPU0_SA_CB<0>")
	)
	(segment
		(start 261.830312 -278.491696)
		(end 261.381494 -278.491696)
		(width 0.20066)
		(layer "F.Cu")
		(net "M_D_CPU0_SA_CB<0>")
	)
	(segment
		(start 262.255254 -278.916638)
		(end 261.830312 -278.491696)
		(width 0.20066)
		(layer "F.Cu")
		(net "M_D_CPU0_SA_CB<0>")
	)
	(segment
		(start 258.11226 -279.155398)
		(end 257.653536 -279.155398)
		(width 0.20066)
		(layer "F.Cu")
		(net "M_D_CPU0_SA_CB<0>")
	)
	(segment
		(start 347.002862 -263.964674)
		(end 347.002862 -264.50036)
		(width 0.20066)
		(layer "F.Cu")
		(net "M_D_CPU0_SA_CB<0>")
	)
	(segment
		(start 259.064506 -278.491696)
		(end 259.056378 -278.483568)
		(width 0.101854)
		(layer "F.Cu")
		(net "M_D_CPU0_SA_CB<0>")
	)
	(segment
		(start 263.624314 -278.916638)
		(end 262.255254 -278.916638)
		(width 0.20066)
		(layer "F.Cu")
		(net "M_D_CPU0_SA_CB<0>")
	)
	(segment
		(start 258.49453 -278.483568)
		(end 258.28498 -278.693118)
		(width 0.20066)
		(layer "F.Cu")
		(net "M_D_CPU0_SA_CB<0>")
	)
	(segment
		(start 347.003116 -263.96442)
		(end 347.002862 -263.964674)
		(width 0.20066)
		(layer "F.Cu")
		(net "M_D_CPU0_SA_CB<0>")
	)
	(segment
		(start 258.28498 -278.693118)
		(end 258.28498 -278.982678)
		(width 0.20066)
		(layer "F.Cu")
		(net "M_D_CPU0_SA_CB<0>")
	)
	(segment
		(start 257.653536 -279.155398)
		(end 257.414776 -278.916638)
		(width 0.20066)
		(layer "F.Cu")
		(net "M_D_CPU0_SA_CB<0>")
	)
	(segment
		(start 257.414776 -278.916638)
		(end 256.080514 -278.916638)
		(width 0.20066)
		(layer "F.Cu")
		(net "M_D_CPU0_SA_CB<0>")
	)
	(segment
		(start 259.31241 -278.491696)
		(end 259.064506 -278.491696)
		(width 0.101854)
		(layer "F.Cu")
		(net "M_D_CPU0_SA_CB<0>")
	)
	(segment
		(start 264.729214 -278.916638)
		(end 263.624314 -278.916638)
		(width 0.20066)
		(layer "F.Cu")
		(net "M_D_CPU0_SA_CB<0>")
	)
	(segment
		(start 291.025326 -277.549102)
		(end 290.22548 -276.749256)
		(width 0.18288)
		(layer "In11.Cu")
		(net "M_D_CPU0_SA_CB<0>")
	)
	(segment
		(start 270.285972 -279.106884)
		(end 269.758414 -279.106884)
		(width 0.18288)
		(layer "In11.Cu")
		(net "M_D_CPU0_SA_CB<0>")
	)
	(segment
		(start 297.25112 -277.982426)
		(end 296.075862 -277.982426)
		(width 0.18288)
		(layer "In11.Cu")
		(net "M_D_CPU0_SA_CB<0>")
	)
	(segment
		(start 331.123544 -265.930634)
		(end 330.903072 -265.930634)
		(width 0.088646)
		(layer "In11.Cu")
		(net "M_D_CPU0_SA_CB<0>")
	)
	(segment
		(start 291.683694 -277.728426)
		(end 291.353494 -277.728426)
		(width 0.18288)
		(layer "In11.Cu")
		(net "M_D_CPU0_SA_CB<0>")
	)
	(segment
		(start 287.391094 -276.914864)
		(end 286.0802 -276.914864)
		(width 0.18288)
		(layer "In11.Cu")
		(net "M_D_CPU0_SA_CB<0>")
	)
	(segment
		(start 341.096346 -264.998454)
		(end 341.081614 -264.989818)
		(width 0.088646)
		(layer "In11.Cu")
		(net "M_D_CPU0_SA_CB<0>")
	)
	(segment
		(start 310.57088 -275.913342)
		(end 306.983892 -275.913342)
		(width 0.18288)
		(layer "In11.Cu")
		(net "M_D_CPU0_SA_CB<0>")
	)
	(segment
		(start 277.535894 -277.576026)
		(end 276.621494 -277.779226)
		(width 0.18288)
		(layer "In11.Cu")
		(net "M_D_CPU0_SA_CB<0>")
	)
	(segment
		(start 331.21219 -265.841988)
		(end 331.123544 -265.930634)
		(width 0.088646)
		(layer "In11.Cu")
		(net "M_D_CPU0_SA_CB<0>")
	)
	(segment
		(start 269.758414 -279.106884)
		(end 269.145766 -278.494236)
		(width 0.18288)
		(layer "In11.Cu")
		(net "M_D_CPU0_SA_CB<0>")
	)
	(segment
		(start 338.272374 -264.995914)
		(end 338.26196 -264.989818)
		(width 0.088646)
		(layer "In11.Cu")
		(net "M_D_CPU0_SA_CB<0>")
	)
	(segment
		(start 339.767164 -264.989818)
		(end 339.75675 -264.995914)
		(width 0.088646)
		(layer "In11.Cu")
		(net "M_D_CPU0_SA_CB<0>")
	)
	(segment
		(start 285.590234 -277.40483)
		(end 284.875732 -277.40483)
		(width 0.18288)
		(layer "In11.Cu")
		(net "M_D_CPU0_SA_CB<0>")
	)
	(segment
		(start 347.315536 -264.50036)
		(end 347.37294 -264.442956)
		(width 0.088646)
		(layer "In11.Cu")
		(net "M_D_CPU0_SA_CB<0>")
	)
	(segment
		(start 346.35186 -264.986262)
		(end 346.345764 -264.989818)
		(width 0.088646)
		(layer "In11.Cu")
		(net "M_D_CPU0_SA_CB<0>")
	)
	(segment
		(start 342.036146 -264.998454)
		(end 342.021414 -264.989818)
		(width 0.088646)
		(layer "In11.Cu")
		(net "M_D_CPU0_SA_CB<0>")
	)
	(segment
		(start 266.833604 -279.534366)
		(end 266.833604 -279.703276)
		(width 0.18288)
		(layer "In11.Cu")
		(net "M_D_CPU0_SA_CB<0>")
	)
	(segment
		(start 266.132564 -279.703276)
		(end 266.132564 -279.534366)
		(width 0.18288)
		(layer "In11.Cu")
		(net "M_D_CPU0_SA_CB<0>")
	)
	(segment
		(start 286.0802 -276.914864)
		(end 285.590234 -277.40483)
		(width 0.18288)
		(layer "In11.Cu")
		(net "M_D_CPU0_SA_CB<0>")
	)
	(segment
		(start 311.514236 -274.969986)
		(end 310.57088 -275.913342)
		(width 0.18288)
		(layer "In11.Cu")
		(net "M_D_CPU0_SA_CB<0>")
	)
	(segment
		(start 288.47796 -276.749256)
		(end 287.391094 -276.914864)
		(width 0.18288)
		(layer "In11.Cu")
		(net "M_D_CPU0_SA_CB<0>")
	)
	(segment
		(start 306.983892 -275.913342)
		(end 306.860194 -275.963126)
		(width 0.18288)
		(layer "In11.Cu")
		(net "M_D_CPU0_SA_CB<0>")
	)
	(segment
		(start 291.353494 -277.728426)
		(end 291.025326 -277.549102)
		(width 0.18288)
		(layer "In11.Cu")
		(net "M_D_CPU0_SA_CB<0>")
	)
	(segment
		(start 269.145766 -278.494236)
		(end 267.873734 -278.494236)
		(width 0.18288)
		(layer "In11.Cu")
		(net "M_D_CPU0_SA_CB<0>")
	)
	(segment
		(start 306.860194 -275.963126)
		(end 306.6796 -276.14372)
		(width 0.18288)
		(layer "In11.Cu")
		(net "M_D_CPU0_SA_CB<0>")
	)
	(segment
		(start 276.621494 -277.779226)
		(end 273.420332 -278.342344)
		(width 0.18288)
		(layer "In11.Cu")
		(net "M_D_CPU0_SA_CB<0>")
	)
	(segment
		(start 340.151974 -264.995914)
		(end 340.14156 -264.989818)
		(width 0.088646)
		(layer "In11.Cu")
		(net "M_D_CPU0_SA_CB<0>")
	)
	(segment
		(start 295.566338 -278.49195)
		(end 294.554402 -278.49195)
		(width 0.18288)
		(layer "In11.Cu")
		(net "M_D_CPU0_SA_CB<0>")
	)
	(segment
		(start 282.997148 -277.640796)
		(end 282.149296 -278.488648)
		(width 0.18288)
		(layer "In11.Cu")
		(net "M_D_CPU0_SA_CB<0>")
	)
	(segment
		(start 300.483524 -277.639018)
		(end 297.594528 -277.639018)
		(width 0.18288)
		(layer "In11.Cu")
		(net "M_D_CPU0_SA_CB<0>")
	)
	(segment
		(start 301.13224 -276.990302)
		(end 300.483524 -277.639018)
		(width 0.18288)
		(layer "In11.Cu")
		(net "M_D_CPU0_SA_CB<0>")
	)
	(segment
		(start 265.939524 -279.341326)
		(end 265.153902 -279.341326)
		(width 0.18288)
		(layer "In11.Cu")
		(net "M_D_CPU0_SA_CB<0>")
	)
	(segment
		(start 273.420332 -278.342344)
		(end 270.285972 -279.106884)
		(width 0.18288)
		(layer "In11.Cu")
		(net "M_D_CPU0_SA_CB<0>")
	)
	(segment
		(start 296.075862 -277.982426)
		(end 295.566338 -278.49195)
		(width 0.18288)
		(layer "In11.Cu")
		(net "M_D_CPU0_SA_CB<0>")
	)
	(segment
		(start 306.6796 -276.14372)
		(end 302.040798 -276.990302)
		(width 0.18288)
		(layer "In11.Cu")
		(net "M_D_CPU0_SA_CB<0>")
	)
	(segment
		(start 331.21219 -265.650218)
		(end 331.21219 -265.841988)
		(width 0.088646)
		(layer "In11.Cu")
		(net "M_D_CPU0_SA_CB<0>")
	)
	(segment
		(start 331.796898 -265.06551)
		(end 331.21219 -265.650218)
		(width 0.088646)
		(layer "In11.Cu")
		(net "M_D_CPU0_SA_CB<0>")
	)
	(segment
		(start 347.002862 -264.50036)
		(end 347.315536 -264.50036)
		(width 0.088646)
		(layer "In11.Cu")
		(net "M_D_CPU0_SA_CB<0>")
	)
	(segment
		(start 324.371716 -265.930634)
		(end 315.332364 -274.969986)
		(width 0.18288)
		(layer "In11.Cu")
		(net "M_D_CPU0_SA_CB<0>")
	)
	(segment
		(start 284.875732 -277.40483)
		(end 284.639766 -277.640796)
		(width 0.18288)
		(layer "In11.Cu")
		(net "M_D_CPU0_SA_CB<0>")
	)
	(segment
		(start 266.640564 -279.896316)
		(end 266.325604 -279.896316)
		(width 0.18288)
		(layer "In11.Cu")
		(net "M_D_CPU0_SA_CB<0>")
	)
	(segment
		(start 293.176452 -277.751794)
		(end 292.819582 -277.550626)
		(width 0.18288)
		(layer "In11.Cu")
		(net "M_D_CPU0_SA_CB<0>")
	)
	(segment
		(start 278.587962 -277.576026)
		(end 277.535894 -277.576026)
		(width 0.18288)
		(layer "In11.Cu")
		(net "M_D_CPU0_SA_CB<0>")
	)
	(segment
		(start 347.19895 -264.181082)
		(end 347.19006 -264.176002)
		(width 0.088646)
		(layer "In11.Cu")
		(net "M_D_CPU0_SA_CB<0>")
	)
	(segment
		(start 342.975946 -264.998454)
		(end 342.961214 -264.989818)
		(width 0.088646)
		(layer "In11.Cu")
		(net "M_D_CPU0_SA_CB<0>")
	)
	(segment
		(start 266.132564 -279.534366)
		(end 265.939524 -279.341326)
		(width 0.18288)
		(layer "In11.Cu")
		(net "M_D_CPU0_SA_CB<0>")
	)
	(segment
		(start 292.819582 -277.550626)
		(end 292.473888 -277.550626)
		(width 0.18288)
		(layer "In11.Cu")
		(net "M_D_CPU0_SA_CB<0>")
	)
	(segment
		(start 344.855546 -264.998454)
		(end 344.840814 -264.989818)
		(width 0.088646)
		(layer "In11.Cu")
		(net "M_D_CPU0_SA_CB<0>")
	)
	(segment
		(start 315.332364 -274.969986)
		(end 311.514236 -274.969986)
		(width 0.18288)
		(layer "In11.Cu")
		(net "M_D_CPU0_SA_CB<0>")
	)
	(segment
		(start 265.153902 -279.341326)
		(end 264.729214 -278.916638)
		(width 0.18288)
		(layer "In11.Cu")
		(net "M_D_CPU0_SA_CB<0>")
	)
	(segment
		(start 346.345764 -264.989818)
		(end 346.33535 -264.995914)
		(width 0.088646)
		(layer "In11.Cu")
		(net "M_D_CPU0_SA_CB<0>")
	)
	(segment
		(start 266.833604 -279.703276)
		(end 266.640564 -279.896316)
		(width 0.18288)
		(layer "In11.Cu")
		(net "M_D_CPU0_SA_CB<0>")
	)
	(segment
		(start 284.639766 -277.640796)
		(end 282.997148 -277.640796)
		(width 0.18288)
		(layer "In11.Cu")
		(net "M_D_CPU0_SA_CB<0>")
	)
	(segment
		(start 290.22548 -276.749256)
		(end 288.47796 -276.749256)
		(width 0.18288)
		(layer "In11.Cu")
		(net "M_D_CPU0_SA_CB<0>")
	)
	(segment
		(start 331.966062 -265.06551)
		(end 331.796898 -265.06551)
		(width 0.088646)
		(layer "In11.Cu")
		(net "M_D_CPU0_SA_CB<0>")
	)
	(segment
		(start 330.903072 -265.930634)
		(end 324.371716 -265.930634)
		(width 0.18288)
		(layer "In11.Cu")
		(net "M_D_CPU0_SA_CB<0>")
	)
	(segment
		(start 292.473888 -277.550626)
		(end 291.683694 -277.728426)
		(width 0.18288)
		(layer "In11.Cu")
		(net "M_D_CPU0_SA_CB<0>")
	)
	(segment
		(start 294.554402 -278.49195)
		(end 293.176452 -277.751794)
		(width 0.18288)
		(layer "In11.Cu")
		(net "M_D_CPU0_SA_CB<0>")
	)
	(segment
		(start 343.915746 -264.998454)
		(end 343.901014 -264.989818)
		(width 0.088646)
		(layer "In11.Cu")
		(net "M_D_CPU0_SA_CB<0>")
	)
	(segment
		(start 266.325604 -279.896316)
		(end 266.132564 -279.703276)
		(width 0.18288)
		(layer "In11.Cu")
		(net "M_D_CPU0_SA_CB<0>")
	)
	(segment
		(start 297.594528 -277.639018)
		(end 297.25112 -277.982426)
		(width 0.18288)
		(layer "In11.Cu")
		(net "M_D_CPU0_SA_CB<0>")
	)
	(segment
		(start 302.040798 -276.990302)
		(end 301.13224 -276.990302)
		(width 0.18288)
		(layer "In11.Cu")
		(net "M_D_CPU0_SA_CB<0>")
	)
	(segment
		(start 282.149296 -278.488648)
		(end 279.500584 -278.488648)
		(width 0.18288)
		(layer "In11.Cu")
		(net "M_D_CPU0_SA_CB<0>")
	)
	(segment
		(start 267.873734 -278.494236)
		(end 266.833604 -279.534366)
		(width 0.18288)
		(layer "In11.Cu")
		(net "M_D_CPU0_SA_CB<0>")
	)
	(segment
		(start 346.628466 -264.491724)
		(end 346.628466 -264.50036)
		(width 0.088646)
		(layer "In11.Cu")
		(net "M_D_CPU0_SA_CB<0>")
	)
	(segment
		(start 279.500584 -278.488648)
		(end 278.587962 -277.576026)
		(width 0.18288)
		(layer "In11.Cu")
		(net "M_D_CPU0_SA_CB<0>")
	)
	(arc
		(start 347.19006 -264.176002)
		(mid 347.002862 -264.125859)
		(end 346.815664 -264.176002)
		(width 0.088646)
		(layer "In11.Cu")
		(net "M_D_CPU0_SA_CB<0>")
	)
	(arc
		(start 342.586818 -264.989818)
		(mid 342.312619 -265.065653)
		(end 342.036146 -264.998454)
		(width 0.088646)
		(layer "In11.Cu")
		(net "M_D_CPU0_SA_CB<0>")
	)
	(arc
		(start 344.840814 -264.989818)
		(mid 344.653616 -264.939675)
		(end 344.466418 -264.989818)
		(width 0.088646)
		(layer "In11.Cu")
		(net "M_D_CPU0_SA_CB<0>")
	)
	(arc
		(start 344.466418 -264.989818)
		(mid 344.192219 -265.065653)
		(end 343.915746 -264.998454)
		(width 0.088646)
		(layer "In11.Cu")
		(net "M_D_CPU0_SA_CB<0>")
	)
	(arc
		(start 342.961214 -264.989818)
		(mid 342.774016 -264.939675)
		(end 342.586818 -264.989818)
		(width 0.088646)
		(layer "In11.Cu")
		(net "M_D_CPU0_SA_CB<0>")
	)
	(arc
		(start 335.068164 -264.989818)
		(mid 334.785462 -265.065594)
		(end 334.50276 -264.989818)
		(width 0.088646)
		(layer "In11.Cu")
		(net "M_D_CPU0_SA_CB<0>")
	)
	(arc
		(start 332.248764 -264.989818)
		(mid 332.112395 -265.04626)
		(end 331.966062 -265.06551)
		(width 0.088646)
		(layer "In11.Cu")
		(net "M_D_CPU0_SA_CB<0>")
	)
	(arc
		(start 332.62316 -264.989818)
		(mid 332.435962 -264.939675)
		(end 332.248764 -264.989818)
		(width 0.088646)
		(layer "In11.Cu")
		(net "M_D_CPU0_SA_CB<0>")
	)
	(arc
		(start 342.021414 -264.989818)
		(mid 341.834216 -264.939675)
		(end 341.647018 -264.989818)
		(width 0.088646)
		(layer "In11.Cu")
		(net "M_D_CPU0_SA_CB<0>")
	)
	(arc
		(start 334.50276 -264.989818)
		(mid 334.315562 -264.939675)
		(end 334.128364 -264.989818)
		(width 0.088646)
		(layer "In11.Cu")
		(net "M_D_CPU0_SA_CB<0>")
	)
	(arc
		(start 346.33535 -264.995914)
		(mid 346.057172 -265.065637)
		(end 345.780614 -264.989818)
		(width 0.088646)
		(layer "In11.Cu")
		(net "M_D_CPU0_SA_CB<0>")
	)
	(arc
		(start 341.081614 -264.989818)
		(mid 340.894416 -264.939675)
		(end 340.707218 -264.989818)
		(width 0.088646)
		(layer "In11.Cu")
		(net "M_D_CPU0_SA_CB<0>")
	)
	(arc
		(start 334.128364 -264.989818)
		(mid 333.845662 -265.065594)
		(end 333.56296 -264.989818)
		(width 0.088646)
		(layer "In11.Cu")
		(net "M_D_CPU0_SA_CB<0>")
	)
	(arc
		(start 333.188564 -264.989818)
		(mid 332.905862 -265.065594)
		(end 332.62316 -264.989818)
		(width 0.088646)
		(layer "In11.Cu")
		(net "M_D_CPU0_SA_CB<0>")
	)
	(arc
		(start 336.007964 -264.989818)
		(mid 335.725262 -265.065594)
		(end 335.44256 -264.989818)
		(width 0.088646)
		(layer "In11.Cu")
		(net "M_D_CPU0_SA_CB<0>")
	)
	(arc
		(start 336.38236 -264.989818)
		(mid 336.195162 -264.939675)
		(end 336.007964 -264.989818)
		(width 0.088646)
		(layer "In11.Cu")
		(net "M_D_CPU0_SA_CB<0>")
	)
	(arc
		(start 337.887564 -264.989818)
		(mid 337.604862 -265.065594)
		(end 337.32216 -264.989818)
		(width 0.088646)
		(layer "In11.Cu")
		(net "M_D_CPU0_SA_CB<0>")
	)
	(arc
		(start 346.815664 -264.176002)
		(mid 346.680731 -264.309356)
		(end 346.628466 -264.491724)
		(width 0.088646)
		(layer "In11.Cu")
		(net "M_D_CPU0_SA_CB<0>")
	)
	(arc
		(start 338.827618 -264.989818)
		(mid 338.550805 -265.065688)
		(end 338.272374 -264.995914)
		(width 0.088646)
		(layer "In11.Cu")
		(net "M_D_CPU0_SA_CB<0>")
	)
	(arc
		(start 339.75675 -264.995914)
		(mid 339.478572 -265.065637)
		(end 339.202014 -264.989818)
		(width 0.088646)
		(layer "In11.Cu")
		(net "M_D_CPU0_SA_CB<0>")
	)
	(arc
		(start 338.26196 -264.989818)
		(mid 338.074762 -264.939675)
		(end 337.887564 -264.989818)
		(width 0.088646)
		(layer "In11.Cu")
		(net "M_D_CPU0_SA_CB<0>")
	)
	(arc
		(start 346.628466 -264.50036)
		(mid 346.554475 -264.779926)
		(end 346.35186 -264.986262)
		(width 0.088646)
		(layer "In11.Cu")
		(net "M_D_CPU0_SA_CB<0>")
	)
	(arc
		(start 347.37294 -264.442956)
		(mid 347.314784 -264.292843)
		(end 347.19895 -264.181082)
		(width 0.088646)
		(layer "In11.Cu")
		(net "M_D_CPU0_SA_CB<0>")
	)
	(arc
		(start 341.647018 -264.989818)
		(mid 341.372819 -265.065653)
		(end 341.096346 -264.998454)
		(width 0.088646)
		(layer "In11.Cu")
		(net "M_D_CPU0_SA_CB<0>")
	)
	(arc
		(start 335.44256 -264.989818)
		(mid 335.255362 -264.939675)
		(end 335.068164 -264.989818)
		(width 0.088646)
		(layer "In11.Cu")
		(net "M_D_CPU0_SA_CB<0>")
	)
	(arc
		(start 345.780614 -264.989818)
		(mid 345.593416 -264.939675)
		(end 345.406218 -264.989818)
		(width 0.088646)
		(layer "In11.Cu")
		(net "M_D_CPU0_SA_CB<0>")
	)
	(arc
		(start 333.56296 -264.989818)
		(mid 333.375762 -264.939675)
		(end 333.188564 -264.989818)
		(width 0.088646)
		(layer "In11.Cu")
		(net "M_D_CPU0_SA_CB<0>")
	)
	(arc
		(start 337.32216 -264.989818)
		(mid 337.134962 -264.939675)
		(end 336.947764 -264.989818)
		(width 0.088646)
		(layer "In11.Cu")
		(net "M_D_CPU0_SA_CB<0>")
	)
	(arc
		(start 343.526618 -264.989818)
		(mid 343.252419 -265.065653)
		(end 342.975946 -264.998454)
		(width 0.088646)
		(layer "In11.Cu")
		(net "M_D_CPU0_SA_CB<0>")
	)
	(arc
		(start 343.901014 -264.989818)
		(mid 343.713816 -264.939675)
		(end 343.526618 -264.989818)
		(width 0.088646)
		(layer "In11.Cu")
		(net "M_D_CPU0_SA_CB<0>")
	)
	(arc
		(start 340.14156 -264.989818)
		(mid 339.954362 -264.939675)
		(end 339.767164 -264.989818)
		(width 0.088646)
		(layer "In11.Cu")
		(net "M_D_CPU0_SA_CB<0>")
	)
	(arc
		(start 339.202014 -264.989818)
		(mid 339.014816 -264.939675)
		(end 338.827618 -264.989818)
		(width 0.088646)
		(layer "In11.Cu")
		(net "M_D_CPU0_SA_CB<0>")
	)
	(arc
		(start 340.707218 -264.989818)
		(mid 340.430405 -265.065688)
		(end 340.151974 -264.995914)
		(width 0.088646)
		(layer "In11.Cu")
		(net "M_D_CPU0_SA_CB<0>")
	)
	(arc
		(start 336.947764 -264.989818)
		(mid 336.665062 -265.065594)
		(end 336.38236 -264.989818)
		(width 0.088646)
		(layer "In11.Cu")
		(net "M_D_CPU0_SA_CB<0>")
	)
	(arc
		(start 345.406218 -264.989818)
		(mid 345.132019 -265.065653)
		(end 344.855546 -264.998454)
		(width 0.088646)
		(layer "In11.Cu")
		(net "M_D_CPU0_SA_CB<0>")
	)
	(segment
		(start 264.729214 -261.066788)
		(end 263.624314 -261.066788)
		(width 0.20066)
		(layer "F.Cu")
		(net "M_D_CPU0_SA_CA<6>")
	)
	(segment
		(start 347.83268 -248.527824)
		(end 347.83268 -247.992138)
		(width 0.20066)
		(layer "F.Cu")
		(net "M_D_CPU0_SA_CA<6>")
	)
	(segment
		(start 263.624314 -261.066788)
		(end 261.984998 -261.066788)
		(width 0.20066)
		(layer "F.Cu")
		(net "M_D_CPU0_SA_CA<6>")
	)
	(segment
		(start 261.381494 -260.641846)
		(end 261.050786 -260.641846)
		(width 0.101854)
		(layer "F.Cu")
		(net "M_D_CPU0_SA_CA<6>")
	)
	(segment
		(start 258.44754 -260.632956)
		(end 258.28498 -260.795516)
		(width 0.20066)
		(layer "F.Cu")
		(net "M_D_CPU0_SA_CA<6>")
	)
	(segment
		(start 261.050786 -260.641846)
		(end 259.065268 -260.641846)
		(width 0.1016)
		(layer "F.Cu")
		(net "M_D_CPU0_SA_CA<6>")
	)
	(segment
		(start 347.832934 -248.528078)
		(end 347.83268 -248.527824)
		(width 0.20066)
		(layer "F.Cu")
		(net "M_D_CPU0_SA_CA<6>")
	)
	(segment
		(start 259.056378 -260.632956)
		(end 258.44754 -260.632956)
		(width 0.20066)
		(layer "F.Cu")
		(net "M_D_CPU0_SA_CA<6>")
	)
	(segment
		(start 258.28498 -261.123684)
		(end 258.130548 -261.278116)
		(width 0.20066)
		(layer "F.Cu")
		(net "M_D_CPU0_SA_CA<6>")
	)
	(segment
		(start 261.984998 -261.066788)
		(end 261.560056 -260.641846)
		(width 0.20066)
		(layer "F.Cu")
		(net "M_D_CPU0_SA_CA<6>")
	)
	(segment
		(start 257.414776 -261.066788)
		(end 256.080514 -261.066788)
		(width 0.20066)
		(layer "F.Cu")
		(net "M_D_CPU0_SA_CA<6>")
	)
	(segment
		(start 261.560056 -260.641846)
		(end 261.381494 -260.641846)
		(width 0.20066)
		(layer "F.Cu")
		(net "M_D_CPU0_SA_CA<6>")
	)
	(segment
		(start 259.065268 -260.641846)
		(end 259.056378 -260.632956)
		(width 0.1016)
		(layer "F.Cu")
		(net "M_D_CPU0_SA_CA<6>")
	)
	(segment
		(start 257.626104 -261.278116)
		(end 257.414776 -261.066788)
		(width 0.20066)
		(layer "F.Cu")
		(net "M_D_CPU0_SA_CA<6>")
	)
	(segment
		(start 258.130548 -261.278116)
		(end 257.626104 -261.278116)
		(width 0.20066)
		(layer "F.Cu")
		(net "M_D_CPU0_SA_CA<6>")
	)
	(segment
		(start 258.28498 -260.795516)
		(end 258.28498 -261.123684)
		(width 0.20066)
		(layer "F.Cu")
		(net "M_D_CPU0_SA_CA<6>")
	)
	(segment
		(start 290.71189 -257.073908)
		(end 290.224972 -257.560826)
		(width 0.18288)
		(layer "In11.Cu")
		(net "M_D_CPU0_SA_CA<6>")
	)
	(segment
		(start 286.36468 -257.560826)
		(end 285.877762 -257.073908)
		(width 0.18288)
		(layer "In11.Cu")
		(net "M_D_CPU0_SA_CA<6>")
	)
	(segment
		(start 297.926252 -257.481578)
		(end 293.829232 -257.481578)
		(width 0.18288)
		(layer "In11.Cu")
		(net "M_D_CPU0_SA_CA<6>")
	)
	(segment
		(start 271.860264 -259.223256)
		(end 270.463264 -260.620256)
		(width 0.18288)
		(layer "In11.Cu")
		(net "M_D_CPU0_SA_CA<6>")
	)
	(segment
		(start 348.57055 -248.30786)
		(end 348.585282 -248.316496)
		(width 0.088646)
		(layer "In11.Cu")
		(net "M_D_CPU0_SA_CA<6>")
	)
	(segment
		(start 347.83268 -247.992138)
		(end 347.989144 -248.263156)
		(width 0.088646)
		(layer "In11.Cu")
		(net "M_D_CPU0_SA_CA<6>")
	)
	(segment
		(start 349.33763 -249.610118)
		(end 349.337884 -249.610372)
		(width 0.088646)
		(layer "In11.Cu")
		(net "M_D_CPU0_SA_CA<6>")
	)
	(segment
		(start 285.877762 -257.073908)
		(end 283.246322 -257.073908)
		(width 0.18288)
		(layer "In11.Cu")
		(net "M_D_CPU0_SA_CA<6>")
	)
	(segment
		(start 314.988956 -255.500632)
		(end 313.333638 -256.186178)
		(width 0.18288)
		(layer "In11.Cu")
		(net "M_D_CPU0_SA_CA<6>")
	)
	(segment
		(start 274.850098 -257.560826)
		(end 273.928332 -257.942588)
		(width 0.18288)
		(layer "In11.Cu")
		(net "M_D_CPU0_SA_CA<6>")
	)
	(segment
		(start 346.567252 -253.54153)
		(end 342.942672 -253.54153)
		(width 0.088646)
		(layer "In11.Cu")
		(net "M_D_CPU0_SA_CA<6>")
	)
	(segment
		(start 278.324056 -257.064002)
		(end 275.621496 -257.064002)
		(width 0.18288)
		(layer "In11.Cu")
		(net "M_D_CPU0_SA_CA<6>")
	)
	(segment
		(start 275.621496 -257.064002)
		(end 275.124672 -257.560826)
		(width 0.18288)
		(layer "In11.Cu")
		(net "M_D_CPU0_SA_CA<6>")
	)
	(segment
		(start 273.928332 -257.942588)
		(end 273.204686 -258.666234)
		(width 0.18288)
		(layer "In11.Cu")
		(net "M_D_CPU0_SA_CA<6>")
	)
	(segment
		(start 329.60183 -254.435356)
		(end 328.108056 -255.92913)
		(width 0.18288)
		(layer "In11.Cu")
		(net "M_D_CPU0_SA_CA<6>")
	)
	(segment
		(start 265.760962 -261.49427)
		(end 264.729214 -261.066788)
		(width 0.18288)
		(layer "In11.Cu")
		(net "M_D_CPU0_SA_CA<6>")
	)
	(segment
		(start 332.643226 -254.435356)
		(end 329.60183 -254.435356)
		(width 0.18288)
		(layer "In11.Cu")
		(net "M_D_CPU0_SA_CA<6>")
	)
	(segment
		(start 313.333638 -256.186178)
		(end 311.713372 -256.857246)
		(width 0.18288)
		(layer "In11.Cu")
		(net "M_D_CPU0_SA_CA<6>")
	)
	(segment
		(start 335.072228 -253.441708)
		(end 334.42529 -254.088646)
		(width 0.18288)
		(layer "In11.Cu")
		(net "M_D_CPU0_SA_CA<6>")
	)
	(segment
		(start 342.84285 -253.441708)
		(end 342.261698 -253.441708)
		(width 0.088646)
		(layer "In11.Cu")
		(net "M_D_CPU0_SA_CA<6>")
	)
	(segment
		(start 348.867984 -248.791984)
		(end 348.867984 -248.814844)
		(width 0.088646)
		(layer "In11.Cu")
		(net "M_D_CPU0_SA_CA<6>")
	)
	(segment
		(start 300.860206 -257.073908)
		(end 298.333922 -257.073908)
		(width 0.18288)
		(layer "In11.Cu")
		(net "M_D_CPU0_SA_CA<6>")
	)
	(segment
		(start 290.224972 -257.560826)
		(end 286.36468 -257.560826)
		(width 0.18288)
		(layer "In11.Cu")
		(net "M_D_CPU0_SA_CA<6>")
	)
	(segment
		(start 301.347124 -257.560826)
		(end 300.860206 -257.073908)
		(width 0.18288)
		(layer "In11.Cu")
		(net "M_D_CPU0_SA_CA<6>")
	)
	(segment
		(start 323.108066 -255.92913)
		(end 322.679568 -255.500632)
		(width 0.18288)
		(layer "In11.Cu")
		(net "M_D_CPU0_SA_CA<6>")
	)
	(segment
		(start 293.829232 -257.481578)
		(end 293.421562 -257.073908)
		(width 0.18288)
		(layer "In11.Cu")
		(net "M_D_CPU0_SA_CA<6>")
	)
	(segment
		(start 332.989936 -254.088646)
		(end 332.643226 -254.435356)
		(width 0.18288)
		(layer "In11.Cu")
		(net "M_D_CPU0_SA_CA<6>")
	)
	(segment
		(start 278.82088 -257.560826)
		(end 278.324056 -257.064002)
		(width 0.18288)
		(layer "In11.Cu")
		(net "M_D_CPU0_SA_CA<6>")
	)
	(segment
		(start 347.989144 -248.263156)
		(end 348.078298 -248.287032)
		(width 0.088646)
		(layer "In11.Cu")
		(net "M_D_CPU0_SA_CA<6>")
	)
	(segment
		(start 273.204686 -258.666234)
		(end 271.860264 -259.223256)
		(width 0.18288)
		(layer "In11.Cu")
		(net "M_D_CPU0_SA_CA<6>")
	)
	(segment
		(start 307.493416 -256.857246)
		(end 305.794664 -257.560826)
		(width 0.18288)
		(layer "In11.Cu")
		(net "M_D_CPU0_SA_CA<6>")
	)
	(segment
		(start 275.124672 -257.560826)
		(end 274.850098 -257.560826)
		(width 0.18288)
		(layer "In11.Cu")
		(net "M_D_CPU0_SA_CA<6>")
	)
	(segment
		(start 283.246322 -257.073908)
		(end 282.759404 -257.560826)
		(width 0.18288)
		(layer "In11.Cu")
		(net "M_D_CPU0_SA_CA<6>")
	)
	(segment
		(start 349.337884 -249.610372)
		(end 349.337884 -250.770898)
		(width 0.088646)
		(layer "In11.Cu")
		(net "M_D_CPU0_SA_CA<6>")
	)
	(segment
		(start 328.108056 -255.92913)
		(end 323.108066 -255.92913)
		(width 0.18288)
		(layer "In11.Cu")
		(net "M_D_CPU0_SA_CA<6>")
	)
	(segment
		(start 293.421562 -257.073908)
		(end 290.71189 -257.073908)
		(width 0.18288)
		(layer "In11.Cu")
		(net "M_D_CPU0_SA_CA<6>")
	)
	(segment
		(start 311.713372 -256.857246)
		(end 307.493416 -256.857246)
		(width 0.18288)
		(layer "In11.Cu")
		(net "M_D_CPU0_SA_CA<6>")
	)
	(segment
		(start 270.080232 -260.779006)
		(end 269.83817 -260.779006)
		(width 0.18288)
		(layer "In11.Cu")
		(net "M_D_CPU0_SA_CA<6>")
	)
	(segment
		(start 342.942672 -253.54153)
		(end 342.84285 -253.441708)
		(width 0.088646)
		(layer "In11.Cu")
		(net "M_D_CPU0_SA_CA<6>")
	)
	(segment
		(start 349.337884 -250.770898)
		(end 346.567252 -253.54153)
		(width 0.088646)
		(layer "In11.Cu")
		(net "M_D_CPU0_SA_CA<6>")
	)
	(segment
		(start 269.83817 -260.779006)
		(end 269.122906 -261.49427)
		(width 0.18288)
		(layer "In11.Cu")
		(net "M_D_CPU0_SA_CA<6>")
	)
	(segment
		(start 298.333922 -257.073908)
		(end 297.926252 -257.481578)
		(width 0.18288)
		(layer "In11.Cu")
		(net "M_D_CPU0_SA_CA<6>")
	)
	(segment
		(start 342.261698 -253.441708)
		(end 335.072228 -253.441708)
		(width 0.18288)
		(layer "In11.Cu")
		(net "M_D_CPU0_SA_CA<6>")
	)
	(segment
		(start 282.759404 -257.560826)
		(end 278.82088 -257.560826)
		(width 0.18288)
		(layer "In11.Cu")
		(net "M_D_CPU0_SA_CA<6>")
	)
	(segment
		(start 270.463264 -260.620256)
		(end 270.080232 -260.779006)
		(width 0.18288)
		(layer "In11.Cu")
		(net "M_D_CPU0_SA_CA<6>")
	)
	(segment
		(start 322.679568 -255.500632)
		(end 314.988956 -255.500632)
		(width 0.18288)
		(layer "In11.Cu")
		(net "M_D_CPU0_SA_CA<6>")
	)
	(segment
		(start 334.42529 -254.088646)
		(end 332.989936 -254.088646)
		(width 0.18288)
		(layer "In11.Cu")
		(net "M_D_CPU0_SA_CA<6>")
	)
	(segment
		(start 305.794664 -257.560826)
		(end 301.347124 -257.560826)
		(width 0.18288)
		(layer "In11.Cu")
		(net "M_D_CPU0_SA_CA<6>")
	)
	(segment
		(start 269.122906 -261.49427)
		(end 265.760962 -261.49427)
		(width 0.18288)
		(layer "In11.Cu")
		(net "M_D_CPU0_SA_CA<6>")
	)
	(arc
		(start 348.867984 -248.814844)
		(mid 348.920254 -248.997209)
		(end 349.055182 -249.130566)
		(width 0.088646)
		(layer "In11.Cu")
		(net "M_D_CPU0_SA_CA<6>")
	)
	(arc
		(start 348.078298 -248.287032)
		(mid 348.326803 -248.241066)
		(end 348.57055 -248.30786)
		(width 0.088646)
		(layer "In11.Cu")
		(net "M_D_CPU0_SA_CA<6>")
	)
	(arc
		(start 349.055182 -249.130566)
		(mid 349.259517 -249.333171)
		(end 349.33763 -249.610118)
		(width 0.088646)
		(layer "In11.Cu")
		(net "M_D_CPU0_SA_CA<6>")
	)
	(arc
		(start 348.585282 -248.316496)
		(mid 348.788763 -248.5173)
		(end 348.867984 -248.791984)
		(width 0.088646)
		(layer "In11.Cu")
		(net "M_D_CPU0_SA_CA<6>")
	)
	(segment
		(start 262.003794 -262.042656)
		(end 261.87781 -261.916672)
		(width 0.20066)
		(layer "F.Cu")
		(net "M_D_CPU0_SA_CA<5>")
	)
	(segment
		(start 265.518646 -262.040878)
		(end 265.518646 -262.192516)
		(width 0.20066)
		(layer "F.Cu")
		(net "M_D_CPU0_SA_CA<5>")
	)
	(segment
		(start 262.514334 -262.341614)
		(end 262.50011 -262.355838)
		(width 0.101854)
		(layer "F.Cu")
		(net "M_D_CPU0_SA_CA<5>")
	)
	(segment
		(start 268.829282 -261.916672)
		(end 267.724382 -261.916672)
		(width 0.20066)
		(layer "F.Cu")
		(net "M_D_CPU0_SA_CA<5>")
	)
	(segment
		(start 262.146288 -262.355838)
		(end 262.003794 -262.213344)
		(width 0.20066)
		(layer "F.Cu")
		(net "M_D_CPU0_SA_CA<5>")
	)
	(segment
		(start 347.942916 -256.361184)
		(end 347.942662 -256.361438)
		(width 0.20066)
		(layer "F.Cu")
		(net "M_D_CPU0_SA_CA<5>")
	)
	(segment
		(start 266.90828 -261.916672)
		(end 266.700762 -262.12419)
		(width 0.20066)
		(layer "F.Cu")
		(net "M_D_CPU0_SA_CA<5>")
	)
	(segment
		(start 265.64717 -261.912354)
		(end 265.518646 -262.040878)
		(width 0.20066)
		(layer "F.Cu")
		(net "M_D_CPU0_SA_CA<5>")
	)
	(segment
		(start 267.724382 -261.916672)
		(end 266.90828 -261.916672)
		(width 0.20066)
		(layer "F.Cu")
		(net "M_D_CPU0_SA_CA<5>")
	)
	(segment
		(start 262.752332 -262.341614)
		(end 262.514334 -262.341614)
		(width 0.101854)
		(layer "F.Cu")
		(net "M_D_CPU0_SA_CA<5>")
	)
	(segment
		(start 266.25423 -262.12419)
		(end 266.042394 -261.912354)
		(width 0.20066)
		(layer "F.Cu")
		(net "M_D_CPU0_SA_CA<5>")
	)
	(segment
		(start 264.825226 -262.341614)
		(end 262.752332 -262.341614)
		(width 0.1016)
		(layer "F.Cu")
		(net "M_D_CPU0_SA_CA<5>")
	)
	(segment
		(start 266.700762 -262.12419)
		(end 266.25423 -262.12419)
		(width 0.20066)
		(layer "F.Cu")
		(net "M_D_CPU0_SA_CA<5>")
	)
	(segment
		(start 265.369548 -262.341614)
		(end 264.825226 -262.341614)
		(width 0.20066)
		(layer "F.Cu")
		(net "M_D_CPU0_SA_CA<5>")
	)
	(segment
		(start 347.942916 -255.825498)
		(end 347.942916 -256.361184)
		(width 0.20066)
		(layer "F.Cu")
		(net "M_D_CPU0_SA_CA<5>")
	)
	(segment
		(start 261.87781 -261.916672)
		(end 260.180582 -261.916672)
		(width 0.20066)
		(layer "F.Cu")
		(net "M_D_CPU0_SA_CA<5>")
	)
	(segment
		(start 265.518646 -262.192516)
		(end 265.369548 -262.341614)
		(width 0.20066)
		(layer "F.Cu")
		(net "M_D_CPU0_SA_CA<5>")
	)
	(segment
		(start 262.003794 -262.213344)
		(end 262.003794 -262.042656)
		(width 0.20066)
		(layer "F.Cu")
		(net "M_D_CPU0_SA_CA<5>")
	)
	(segment
		(start 262.50011 -262.355838)
		(end 262.146288 -262.355838)
		(width 0.20066)
		(layer "F.Cu")
		(net "M_D_CPU0_SA_CA<5>")
	)
	(segment
		(start 266.042394 -261.912354)
		(end 265.64717 -261.912354)
		(width 0.20066)
		(layer "F.Cu")
		(net "M_D_CPU0_SA_CA<5>")
	)
	(segment
		(start 303.576482 -258.466336)
		(end 303.216818 -258.466336)
		(width 0.18288)
		(layer "In11.Cu")
		(net "M_D_CPU0_SA_CA<5>")
	)
	(segment
		(start 275.292312 -258.194556)
		(end 274.93722 -258.194556)
		(width 0.18288)
		(layer "In11.Cu")
		(net "M_D_CPU0_SA_CA<5>")
	)
	(segment
		(start 269.922752 -261.423912)
		(end 269.429992 -261.916672)
		(width 0.18288)
		(layer "In11.Cu")
		(net "M_D_CPU0_SA_CA<5>")
	)
	(segment
		(start 296.039286 -258.368038)
		(end 295.681146 -258.368038)
		(width 0.18288)
		(layer "In11.Cu")
		(net "M_D_CPU0_SA_CA<5>")
	)
	(segment
		(start 288.71926 -258.273042)
		(end 288.71926 -258.399026)
		(width 0.18288)
		(layer "In11.Cu")
		(net "M_D_CPU0_SA_CA<5>")
	)
	(segment
		(start 345.791028 -255.865884)
		(end 345.780614 -255.87198)
		(width 0.088646)
		(layer "In11.Cu")
		(net "M_D_CPU0_SA_CA<5>")
	)
	(segment
		(start 330.927202 -255.695958)
		(end 328.845672 -255.695958)
		(width 0.18288)
		(layer "In11.Cu")
		(net "M_D_CPU0_SA_CA<5>")
	)
	(segment
		(start 280.393394 -258.520438)
		(end 280.393394 -258.282948)
		(width 0.18288)
		(layer "In11.Cu")
		(net "M_D_CPU0_SA_CA<5>")
	)
	(segment
		(start 293.173658 -257.581908)
		(end 290.99256 -257.581908)
		(width 0.18288)
		(layer "In11.Cu")
		(net "M_D_CPU0_SA_CA<5>")
	)
	(segment
		(start 341.096346 -255.863344)
		(end 341.081614 -255.87198)
		(width 0.088646)
		(layer "In11.Cu")
		(net "M_D_CPU0_SA_CA<5>")
	)
	(segment
		(start 298.546012 -257.581908)
		(end 298.072302 -258.055618)
		(width 0.18288)
		(layer "In11.Cu")
		(net "M_D_CPU0_SA_CA<5>")
	)
	(segment
		(start 328.26706 -256.27457)
		(end 322.84162 -256.27457)
		(width 0.18288)
		(layer "In11.Cu")
		(net "M_D_CPU0_SA_CA<5>")
	)
	(segment
		(start 300.641766 -257.581908)
		(end 298.546012 -257.581908)
		(width 0.18288)
		(layer "In11.Cu")
		(net "M_D_CPU0_SA_CA<5>")
	)
	(segment
		(start 278.06142 -257.572002)
		(end 275.914866 -257.572002)
		(width 0.18288)
		(layer "In11.Cu")
		(net "M_D_CPU0_SA_CA<5>")
	)
	(segment
		(start 301.13986 -258.080002)
		(end 300.641766 -257.581908)
		(width 0.18288)
		(layer "In11.Cu")
		(net "M_D_CPU0_SA_CA<5>")
	)
	(segment
		(start 286.11576 -258.080002)
		(end 285.617666 -257.581908)
		(width 0.18288)
		(layer "In11.Cu")
		(net "M_D_CPU0_SA_CA<5>")
	)
	(segment
		(start 331.691996 -255.796288)
		(end 331.591666 -255.695958)
		(width 0.088646)
		(layer "In11.Cu")
		(net "M_D_CPU0_SA_CA<5>")
	)
	(segment
		(start 288.01822 -258.399026)
		(end 288.01822 -258.273042)
		(width 0.18288)
		(layer "In11.Cu")
		(net "M_D_CPU0_SA_CA<5>")
	)
	(segment
		(start 322.67398 -256.10693)
		(end 314.929266 -256.10693)
		(width 0.18288)
		(layer "In11.Cu")
		(net "M_D_CPU0_SA_CA<5>")
	)
	(segment
		(start 280.393394 -258.282948)
		(end 280.200354 -258.089908)
		(width 0.18288)
		(layer "In11.Cu")
		(net "M_D_CPU0_SA_CA<5>")
	)
	(segment
		(start 331.966062 -255.796288)
		(end 331.691996 -255.796288)
		(width 0.088646)
		(layer "In11.Cu")
		(net "M_D_CPU0_SA_CA<5>")
	)
	(segment
		(start 274.74418 -258.387596)
		(end 274.74418 -258.742688)
		(width 0.18288)
		(layer "In11.Cu")
		(net "M_D_CPU0_SA_CA<5>")
	)
	(segment
		(start 288.01822 -258.273042)
		(end 287.82518 -258.080002)
		(width 0.18288)
		(layer "In11.Cu")
		(net "M_D_CPU0_SA_CA<5>")
	)
	(segment
		(start 285.617666 -257.581908)
		(end 283.466032 -257.581908)
		(width 0.18288)
		(layer "In11.Cu")
		(net "M_D_CPU0_SA_CA<5>")
	)
	(segment
		(start 313.608466 -256.6543)
		(end 312.893964 -257.368802)
		(width 0.18288)
		(layer "In11.Cu")
		(net "M_D_CPU0_SA_CA<5>")
	)
	(segment
		(start 347.31579 -255.889252)
		(end 347.285564 -255.87198)
		(width 0.088646)
		(layer "In11.Cu")
		(net "M_D_CPU0_SA_CA<5>")
	)
	(segment
		(start 280.200354 -258.089908)
		(end 278.579326 -258.089908)
		(width 0.18288)
		(layer "In11.Cu")
		(net "M_D_CPU0_SA_CA<5>")
	)
	(segment
		(start 307.759862 -257.368802)
		(end 306.182776 -258.02209)
		(width 0.18288)
		(layer "In11.Cu")
		(net "M_D_CPU0_SA_CA<5>")
	)
	(segment
		(start 331.591666 -255.695958)
		(end 330.927202 -255.695958)
		(width 0.088646)
		(layer "In11.Cu")
		(net "M_D_CPU0_SA_CA<5>")
	)
	(segment
		(start 337.332828 -255.865884)
		(end 337.322414 -255.87198)
		(width 0.088646)
		(layer "In11.Cu")
		(net "M_D_CPU0_SA_CA<5>")
	)
	(segment
		(start 290.99256 -257.581908)
		(end 290.494466 -258.080002)
		(width 0.18288)
		(layer "In11.Cu")
		(net "M_D_CPU0_SA_CA<5>")
	)
	(segment
		(start 272.913094 -259.745226)
		(end 272.100294 -259.745226)
		(width 0.18288)
		(layer "In11.Cu")
		(net "M_D_CPU0_SA_CA<5>")
	)
	(segment
		(start 295.681146 -258.368038)
		(end 295.368726 -258.055618)
		(width 0.18288)
		(layer "In11.Cu")
		(net "M_D_CPU0_SA_CA<5>")
	)
	(segment
		(start 280.901394 -258.713478)
		(end 280.586434 -258.713478)
		(width 0.18288)
		(layer "In11.Cu")
		(net "M_D_CPU0_SA_CA<5>")
	)
	(segment
		(start 312.893964 -257.368802)
		(end 307.759862 -257.368802)
		(width 0.18288)
		(layer "In11.Cu")
		(net "M_D_CPU0_SA_CA<5>")
	)
	(segment
		(start 275.914866 -257.572002)
		(end 275.292312 -258.194556)
		(width 0.18288)
		(layer "In11.Cu")
		(net "M_D_CPU0_SA_CA<5>")
	)
	(segment
		(start 269.429992 -261.916672)
		(end 268.829282 -261.916672)
		(width 0.18288)
		(layer "In11.Cu")
		(net "M_D_CPU0_SA_CA<5>")
	)
	(segment
		(start 298.072302 -258.055618)
		(end 296.351706 -258.055618)
		(width 0.18288)
		(layer "In11.Cu")
		(net "M_D_CPU0_SA_CA<5>")
	)
	(segment
		(start 343.915746 -255.863344)
		(end 343.901014 -255.87198)
		(width 0.088646)
		(layer "In11.Cu")
		(net "M_D_CPU0_SA_CA<5>")
	)
	(segment
		(start 328.845672 -255.695958)
		(end 328.26706 -256.27457)
		(width 0.18288)
		(layer "In11.Cu")
		(net "M_D_CPU0_SA_CA<5>")
	)
	(segment
		(start 288.71926 -258.399026)
		(end 288.52622 -258.592066)
		(width 0.18288)
		(layer "In11.Cu")
		(net "M_D_CPU0_SA_CA<5>")
	)
	(segment
		(start 305.135788 -258.458208)
		(end 304.753518 -258.075938)
		(width 0.18288)
		(layer "In11.Cu")
		(net "M_D_CPU0_SA_CA<5>")
	)
	(segment
		(start 303.216818 -258.466336)
		(end 302.830484 -258.080002)
		(width 0.18288)
		(layer "In11.Cu")
		(net "M_D_CPU0_SA_CA<5>")
	)
	(segment
		(start 272.100294 -259.745226)
		(end 270.421608 -261.423912)
		(width 0.18288)
		(layer "In11.Cu")
		(net "M_D_CPU0_SA_CA<5>")
	)
	(segment
		(start 281.287474 -258.089908)
		(end 281.094434 -258.282948)
		(width 0.18288)
		(layer "In11.Cu")
		(net "M_D_CPU0_SA_CA<5>")
	)
	(segment
		(start 347.285564 -255.87198)
		(end 347.28531 -255.87198)
		(width 0.088646)
		(layer "In11.Cu")
		(net "M_D_CPU0_SA_CA<5>")
	)
	(segment
		(start 288.21126 -258.592066)
		(end 288.01822 -258.399026)
		(width 0.18288)
		(layer "In11.Cu")
		(net "M_D_CPU0_SA_CA<5>")
	)
	(segment
		(start 273.370294 -259.288026)
		(end 272.913094 -259.745226)
		(width 0.18288)
		(layer "In11.Cu")
		(net "M_D_CPU0_SA_CA<5>")
	)
	(segment
		(start 339.212428 -255.865884)
		(end 339.202014 -255.87198)
		(width 0.088646)
		(layer "In11.Cu")
		(net "M_D_CPU0_SA_CA<5>")
	)
	(segment
		(start 274.93722 -258.194556)
		(end 274.74418 -258.387596)
		(width 0.18288)
		(layer "In11.Cu")
		(net "M_D_CPU0_SA_CA<5>")
	)
	(segment
		(start 296.351706 -258.055618)
		(end 296.039286 -258.368038)
		(width 0.18288)
		(layer "In11.Cu")
		(net "M_D_CPU0_SA_CA<5>")
	)
	(segment
		(start 342.975946 -255.863344)
		(end 342.961214 -255.87198)
		(width 0.088646)
		(layer "In11.Cu")
		(net "M_D_CPU0_SA_CA<5>")
	)
	(segment
		(start 344.855546 -255.863344)
		(end 344.840814 -255.87198)
		(width 0.088646)
		(layer "In11.Cu")
		(net "M_D_CPU0_SA_CA<5>")
	)
	(segment
		(start 302.830484 -258.080002)
		(end 301.13986 -258.080002)
		(width 0.18288)
		(layer "In11.Cu")
		(net "M_D_CPU0_SA_CA<5>")
	)
	(segment
		(start 281.094434 -258.520438)
		(end 280.901394 -258.713478)
		(width 0.18288)
		(layer "In11.Cu")
		(net "M_D_CPU0_SA_CA<5>")
	)
	(segment
		(start 314.929266 -256.10693)
		(end 313.608466 -256.6543)
		(width 0.18288)
		(layer "In11.Cu")
		(net "M_D_CPU0_SA_CA<5>")
	)
	(segment
		(start 340.151974 -255.865884)
		(end 340.14156 -255.87198)
		(width 0.088646)
		(layer "In11.Cu")
		(net "M_D_CPU0_SA_CA<5>")
	)
	(segment
		(start 304.753518 -258.075938)
		(end 303.96688 -258.075938)
		(width 0.18288)
		(layer "In11.Cu")
		(net "M_D_CPU0_SA_CA<5>")
	)
	(segment
		(start 280.586434 -258.713478)
		(end 280.393394 -258.520438)
		(width 0.18288)
		(layer "In11.Cu")
		(net "M_D_CPU0_SA_CA<5>")
	)
	(segment
		(start 274.198842 -259.288026)
		(end 273.370294 -259.288026)
		(width 0.18288)
		(layer "In11.Cu")
		(net "M_D_CPU0_SA_CA<5>")
	)
	(segment
		(start 305.746658 -258.458208)
		(end 305.135788 -258.458208)
		(width 0.18288)
		(layer "In11.Cu")
		(net "M_D_CPU0_SA_CA<5>")
	)
	(segment
		(start 282.958032 -258.089908)
		(end 281.287474 -258.089908)
		(width 0.18288)
		(layer "In11.Cu")
		(net "M_D_CPU0_SA_CA<5>")
	)
	(segment
		(start 281.094434 -258.282948)
		(end 281.094434 -258.520438)
		(width 0.18288)
		(layer "In11.Cu")
		(net "M_D_CPU0_SA_CA<5>")
	)
	(segment
		(start 322.84162 -256.27457)
		(end 322.67398 -256.10693)
		(width 0.18288)
		(layer "In11.Cu")
		(net "M_D_CPU0_SA_CA<5>")
	)
	(segment
		(start 288.52622 -258.592066)
		(end 288.21126 -258.592066)
		(width 0.18288)
		(layer "In11.Cu")
		(net "M_D_CPU0_SA_CA<5>")
	)
	(segment
		(start 306.182776 -258.02209)
		(end 305.746658 -258.458208)
		(width 0.18288)
		(layer "In11.Cu")
		(net "M_D_CPU0_SA_CA<5>")
	)
	(segment
		(start 338.272374 -255.865884)
		(end 338.26196 -255.87198)
		(width 0.088646)
		(layer "In11.Cu")
		(net "M_D_CPU0_SA_CA<5>")
	)
	(segment
		(start 303.96688 -258.075938)
		(end 303.576482 -258.466336)
		(width 0.18288)
		(layer "In11.Cu")
		(net "M_D_CPU0_SA_CA<5>")
	)
	(segment
		(start 293.647368 -258.055618)
		(end 293.173658 -257.581908)
		(width 0.18288)
		(layer "In11.Cu")
		(net "M_D_CPU0_SA_CA<5>")
	)
	(segment
		(start 288.9123 -258.080002)
		(end 288.71926 -258.273042)
		(width 0.18288)
		(layer "In11.Cu")
		(net "M_D_CPU0_SA_CA<5>")
	)
	(segment
		(start 270.421608 -261.423912)
		(end 269.922752 -261.423912)
		(width 0.18288)
		(layer "In11.Cu")
		(net "M_D_CPU0_SA_CA<5>")
	)
	(segment
		(start 290.494466 -258.080002)
		(end 288.9123 -258.080002)
		(width 0.18288)
		(layer "In11.Cu")
		(net "M_D_CPU0_SA_CA<5>")
	)
	(segment
		(start 274.74418 -258.742688)
		(end 274.198842 -259.288026)
		(width 0.18288)
		(layer "In11.Cu")
		(net "M_D_CPU0_SA_CA<5>")
	)
	(segment
		(start 295.368726 -258.055618)
		(end 293.647368 -258.055618)
		(width 0.18288)
		(layer "In11.Cu")
		(net "M_D_CPU0_SA_CA<5>")
	)
	(segment
		(start 278.579326 -258.089908)
		(end 278.06142 -257.572002)
		(width 0.18288)
		(layer "In11.Cu")
		(net "M_D_CPU0_SA_CA<5>")
	)
	(segment
		(start 336.392774 -255.865884)
		(end 336.38236 -255.87198)
		(width 0.088646)
		(layer "In11.Cu")
		(net "M_D_CPU0_SA_CA<5>")
	)
	(segment
		(start 283.466032 -257.581908)
		(end 282.958032 -258.089908)
		(width 0.18288)
		(layer "In11.Cu")
		(net "M_D_CPU0_SA_CA<5>")
	)
	(segment
		(start 287.82518 -258.080002)
		(end 286.11576 -258.080002)
		(width 0.18288)
		(layer "In11.Cu")
		(net "M_D_CPU0_SA_CA<5>")
	)
	(arc
		(start 337.887564 -255.87198)
		(mid 337.611005 -255.796237)
		(end 337.332828 -255.865884)
		(width 0.088646)
		(layer "In11.Cu")
		(net "M_D_CPU0_SA_CA<5>")
	)
	(arc
		(start 334.128364 -255.87198)
		(mid 333.845662 -255.796204)
		(end 333.56296 -255.87198)
		(width 0.088646)
		(layer "In11.Cu")
		(net "M_D_CPU0_SA_CA<5>")
	)
	(arc
		(start 340.707218 -255.87198)
		(mid 340.430405 -255.79611)
		(end 340.151974 -255.865884)
		(width 0.088646)
		(layer "In11.Cu")
		(net "M_D_CPU0_SA_CA<5>")
	)
	(arc
		(start 342.961214 -255.87198)
		(mid 342.774016 -255.922123)
		(end 342.586818 -255.87198)
		(width 0.088646)
		(layer "In11.Cu")
		(net "M_D_CPU0_SA_CA<5>")
	)
	(arc
		(start 332.62316 -255.87198)
		(mid 332.435962 -255.922123)
		(end 332.248764 -255.87198)
		(width 0.088646)
		(layer "In11.Cu")
		(net "M_D_CPU0_SA_CA<5>")
	)
	(arc
		(start 336.38236 -255.87198)
		(mid 336.195162 -255.922123)
		(end 336.007964 -255.87198)
		(width 0.088646)
		(layer "In11.Cu")
		(net "M_D_CPU0_SA_CA<5>")
	)
	(arc
		(start 340.14156 -255.87198)
		(mid 339.954362 -255.922123)
		(end 339.767164 -255.87198)
		(width 0.088646)
		(layer "In11.Cu")
		(net "M_D_CPU0_SA_CA<5>")
	)
	(arc
		(start 334.50276 -255.87198)
		(mid 334.315562 -255.922123)
		(end 334.128364 -255.87198)
		(width 0.088646)
		(layer "In11.Cu")
		(net "M_D_CPU0_SA_CA<5>")
	)
	(arc
		(start 342.586818 -255.87198)
		(mid 342.304116 -255.796204)
		(end 342.021414 -255.87198)
		(width 0.088646)
		(layer "In11.Cu")
		(net "M_D_CPU0_SA_CA<5>")
	)
	(arc
		(start 346.72016 -255.87198)
		(mid 346.532962 -255.922123)
		(end 346.345764 -255.87198)
		(width 0.088646)
		(layer "In11.Cu")
		(net "M_D_CPU0_SA_CA<5>")
	)
	(arc
		(start 341.081614 -255.87198)
		(mid 340.894416 -255.922123)
		(end 340.707218 -255.87198)
		(width 0.088646)
		(layer "In11.Cu")
		(net "M_D_CPU0_SA_CA<5>")
	)
	(arc
		(start 335.068164 -255.87198)
		(mid 334.785462 -255.796204)
		(end 334.50276 -255.87198)
		(width 0.088646)
		(layer "In11.Cu")
		(net "M_D_CPU0_SA_CA<5>")
	)
	(arc
		(start 347.28531 -255.87198)
		(mid 347.002752 -255.796331)
		(end 346.72016 -255.87198)
		(width 0.088646)
		(layer "In11.Cu")
		(net "M_D_CPU0_SA_CA<5>")
	)
	(arc
		(start 339.202014 -255.87198)
		(mid 339.014816 -255.922123)
		(end 338.827618 -255.87198)
		(width 0.088646)
		(layer "In11.Cu")
		(net "M_D_CPU0_SA_CA<5>")
	)
	(arc
		(start 344.840814 -255.87198)
		(mid 344.653616 -255.922123)
		(end 344.466418 -255.87198)
		(width 0.088646)
		(layer "In11.Cu")
		(net "M_D_CPU0_SA_CA<5>")
	)
	(arc
		(start 342.021414 -255.87198)
		(mid 341.834216 -255.922123)
		(end 341.647018 -255.87198)
		(width 0.088646)
		(layer "In11.Cu")
		(net "M_D_CPU0_SA_CA<5>")
	)
	(arc
		(start 345.780614 -255.87198)
		(mid 345.593416 -255.922123)
		(end 345.406218 -255.87198)
		(width 0.088646)
		(layer "In11.Cu")
		(net "M_D_CPU0_SA_CA<5>")
	)
	(arc
		(start 333.188564 -255.87198)
		(mid 332.905862 -255.796204)
		(end 332.62316 -255.87198)
		(width 0.088646)
		(layer "In11.Cu")
		(net "M_D_CPU0_SA_CA<5>")
	)
	(arc
		(start 338.827618 -255.87198)
		(mid 338.550805 -255.79611)
		(end 338.272374 -255.865884)
		(width 0.088646)
		(layer "In11.Cu")
		(net "M_D_CPU0_SA_CA<5>")
	)
	(arc
		(start 345.406218 -255.87198)
		(mid 345.132019 -255.796145)
		(end 344.855546 -255.863344)
		(width 0.088646)
		(layer "In11.Cu")
		(net "M_D_CPU0_SA_CA<5>")
	)
	(arc
		(start 347.942662 -256.361438)
		(mid 347.644172 -256.105502)
		(end 347.31579 -255.889252)
		(width 0.088646)
		(layer "In11.Cu")
		(net "M_D_CPU0_SA_CA<5>")
	)
	(arc
		(start 332.248764 -255.87198)
		(mid 332.112395 -255.815538)
		(end 331.966062 -255.796288)
		(width 0.088646)
		(layer "In11.Cu")
		(net "M_D_CPU0_SA_CA<5>")
	)
	(arc
		(start 336.948018 -255.87198)
		(mid 336.671205 -255.79611)
		(end 336.392774 -255.865884)
		(width 0.088646)
		(layer "In11.Cu")
		(net "M_D_CPU0_SA_CA<5>")
	)
	(arc
		(start 343.901014 -255.87198)
		(mid 343.713816 -255.922123)
		(end 343.526618 -255.87198)
		(width 0.088646)
		(layer "In11.Cu")
		(net "M_D_CPU0_SA_CA<5>")
	)
	(arc
		(start 344.466418 -255.87198)
		(mid 344.192219 -255.796145)
		(end 343.915746 -255.863344)
		(width 0.088646)
		(layer "In11.Cu")
		(net "M_D_CPU0_SA_CA<5>")
	)
	(arc
		(start 335.44256 -255.87198)
		(mid 335.255362 -255.922123)
		(end 335.068164 -255.87198)
		(width 0.088646)
		(layer "In11.Cu")
		(net "M_D_CPU0_SA_CA<5>")
	)
	(arc
		(start 336.007964 -255.87198)
		(mid 335.725262 -255.796204)
		(end 335.44256 -255.87198)
		(width 0.088646)
		(layer "In11.Cu")
		(net "M_D_CPU0_SA_CA<5>")
	)
	(arc
		(start 339.767164 -255.87198)
		(mid 339.490605 -255.796237)
		(end 339.212428 -255.865884)
		(width 0.088646)
		(layer "In11.Cu")
		(net "M_D_CPU0_SA_CA<5>")
	)
	(arc
		(start 341.647018 -255.87198)
		(mid 341.372819 -255.796145)
		(end 341.096346 -255.863344)
		(width 0.088646)
		(layer "In11.Cu")
		(net "M_D_CPU0_SA_CA<5>")
	)
	(arc
		(start 338.26196 -255.87198)
		(mid 338.074762 -255.922123)
		(end 337.887564 -255.87198)
		(width 0.088646)
		(layer "In11.Cu")
		(net "M_D_CPU0_SA_CA<5>")
	)
	(arc
		(start 343.526618 -255.87198)
		(mid 343.252419 -255.796145)
		(end 342.975946 -255.863344)
		(width 0.088646)
		(layer "In11.Cu")
		(net "M_D_CPU0_SA_CA<5>")
	)
	(arc
		(start 333.56296 -255.87198)
		(mid 333.375762 -255.922123)
		(end 333.188564 -255.87198)
		(width 0.088646)
		(layer "In11.Cu")
		(net "M_D_CPU0_SA_CA<5>")
	)
	(arc
		(start 337.322414 -255.87198)
		(mid 337.135216 -255.922123)
		(end 336.948018 -255.87198)
		(width 0.088646)
		(layer "In11.Cu")
		(net "M_D_CPU0_SA_CA<5>")
	)
	(arc
		(start 346.345764 -255.87198)
		(mid 346.069205 -255.796237)
		(end 345.791028 -255.865884)
		(width 0.088646)
		(layer "In11.Cu")
		(net "M_D_CPU0_SA_CA<5>")
	)
	(segment
		(start 258.130548 -262.978138)
		(end 257.626104 -262.978138)
		(width 0.20066)
		(layer "F.Cu")
		(net "M_D_CPU0_SA_CA<4>")
	)
	(segment
		(start 261.381494 -262.341868)
		(end 261.050786 -262.341868)
		(width 0.101854)
		(layer "F.Cu")
		(net "M_D_CPU0_SA_CA<4>")
	)
	(segment
		(start 259.056378 -262.332978)
		(end 258.44754 -262.332978)
		(width 0.20066)
		(layer "F.Cu")
		(net "M_D_CPU0_SA_CA<4>")
	)
	(segment
		(start 259.065268 -262.341868)
		(end 259.056378 -262.332978)
		(width 0.1016)
		(layer "F.Cu")
		(net "M_D_CPU0_SA_CA<4>")
	)
	(segment
		(start 263.624314 -262.76681)
		(end 261.984998 -262.76681)
		(width 0.20066)
		(layer "F.Cu")
		(net "M_D_CPU0_SA_CA<4>")
	)
	(segment
		(start 261.560056 -262.341868)
		(end 261.381494 -262.341868)
		(width 0.20066)
		(layer "F.Cu")
		(net "M_D_CPU0_SA_CA<4>")
	)
	(segment
		(start 261.050786 -262.341868)
		(end 259.065268 -262.341868)
		(width 0.1016)
		(layer "F.Cu")
		(net "M_D_CPU0_SA_CA<4>")
	)
	(segment
		(start 257.414776 -262.76681)
		(end 256.080514 -262.76681)
		(width 0.20066)
		(layer "F.Cu")
		(net "M_D_CPU0_SA_CA<4>")
	)
	(segment
		(start 257.626104 -262.978138)
		(end 257.414776 -262.76681)
		(width 0.20066)
		(layer "F.Cu")
		(net "M_D_CPU0_SA_CA<4>")
	)
	(segment
		(start 258.28498 -262.823706)
		(end 258.130548 -262.978138)
		(width 0.20066)
		(layer "F.Cu")
		(net "M_D_CPU0_SA_CA<4>")
	)
	(segment
		(start 258.28498 -262.495538)
		(end 258.28498 -262.823706)
		(width 0.20066)
		(layer "F.Cu")
		(net "M_D_CPU0_SA_CA<4>")
	)
	(segment
		(start 261.984998 -262.76681)
		(end 261.560056 -262.341868)
		(width 0.20066)
		(layer "F.Cu")
		(net "M_D_CPU0_SA_CA<4>")
	)
	(segment
		(start 347.003116 -256.361184)
		(end 347.002862 -256.361438)
		(width 0.20066)
		(layer "F.Cu")
		(net "M_D_CPU0_SA_CA<4>")
	)
	(segment
		(start 258.44754 -262.332978)
		(end 258.28498 -262.495538)
		(width 0.20066)
		(layer "F.Cu")
		(net "M_D_CPU0_SA_CA<4>")
	)
	(segment
		(start 264.729214 -262.76681)
		(end 263.624314 -262.76681)
		(width 0.20066)
		(layer "F.Cu")
		(net "M_D_CPU0_SA_CA<4>")
	)
	(segment
		(start 347.003116 -255.825498)
		(end 347.003116 -256.361184)
		(width 0.20066)
		(layer "F.Cu")
		(net "M_D_CPU0_SA_CA<4>")
	)
	(segment
		(start 306.797964 -258.994656)
		(end 301.328074 -258.994656)
		(width 0.18288)
		(layer "In11.Cu")
		(net "M_D_CPU0_SA_CA<4>")
	)
	(segment
		(start 339.297264 -256.03708)
		(end 339.282532 -256.045716)
		(width 0.088646)
		(layer "In11.Cu")
		(net "M_D_CPU0_SA_CA<4>")
	)
	(segment
		(start 341.176864 -256.03708)
		(end 341.162132 -256.045716)
		(width 0.088646)
		(layer "In11.Cu")
		(net "M_D_CPU0_SA_CA<4>")
	)
	(segment
		(start 331.574394 -255.986534)
		(end 331.45222 -256.108708)
		(width 0.088646)
		(layer "In11.Cu")
		(net "M_D_CPU0_SA_CA<4>")
	)
	(segment
		(start 293.751762 -258.941062)
		(end 292.900608 -258.089908)
		(width 0.18288)
		(layer "In11.Cu")
		(net "M_D_CPU0_SA_CA<4>")
	)
	(segment
		(start 270.291052 -262.450072)
		(end 269.270734 -262.450072)
		(width 0.18288)
		(layer "In11.Cu")
		(net "M_D_CPU0_SA_CA<4>")
	)
	(segment
		(start 328.410316 -256.620264)
		(end 315.337444 -256.620264)
		(width 0.18288)
		(layer "In11.Cu")
		(net "M_D_CPU0_SA_CA<4>")
	)
	(segment
		(start 295.732962 -259.077714)
		(end 295.59631 -258.941062)
		(width 0.18288)
		(layer "In11.Cu")
		(net "M_D_CPU0_SA_CA<4>")
	)
	(segment
		(start 280.077672 -258.941316)
		(end 278.65832 -258.941316)
		(width 0.18288)
		(layer "In11.Cu")
		(net "M_D_CPU0_SA_CA<4>")
	)
	(segment
		(start 307.89753 -257.880612)
		(end 307.532024 -258.031996)
		(width 0.18288)
		(layer "In11.Cu")
		(net "M_D_CPU0_SA_CA<4>")
	)
	(segment
		(start 345.875864 -256.03708)
		(end 345.861132 -256.045716)
		(width 0.088646)
		(layer "In11.Cu")
		(net "M_D_CPU0_SA_CA<4>")
	)
	(segment
		(start 346.250514 -256.03708)
		(end 346.25026 -256.03708)
		(width 0.088646)
		(layer "In11.Cu")
		(net "M_D_CPU0_SA_CA<4>")
	)
	(segment
		(start 269.16253 -262.341868)
		(end 268.503146 -262.341868)
		(width 0.18288)
		(layer "In11.Cu")
		(net "M_D_CPU0_SA_CA<4>")
	)
	(segment
		(start 268.503146 -262.341868)
		(end 267.60805 -263.236964)
		(width 0.18288)
		(layer "In11.Cu")
		(net "M_D_CPU0_SA_CA<4>")
	)
	(segment
		(start 298.778676 -258.089908)
		(end 297.79087 -259.077714)
		(width 0.18288)
		(layer "In11.Cu")
		(net "M_D_CPU0_SA_CA<4>")
	)
	(segment
		(start 276.147276 -258.089908)
		(end 274.263358 -259.973826)
		(width 0.18288)
		(layer "In11.Cu")
		(net "M_D_CPU0_SA_CA<4>")
	)
	(segment
		(start 346.28074 -256.054606)
		(end 346.250514 -256.03708)
		(width 0.088646)
		(layer "In11.Cu")
		(net "M_D_CPU0_SA_CA<4>")
	)
	(segment
		(start 292.900608 -258.089908)
		(end 291.234876 -258.089908)
		(width 0.18288)
		(layer "In11.Cu")
		(net "M_D_CPU0_SA_CA<4>")
	)
	(segment
		(start 307.088794 -258.475226)
		(end 307.088794 -258.703826)
		(width 0.18288)
		(layer "In11.Cu")
		(net "M_D_CPU0_SA_CA<4>")
	)
	(segment
		(start 274.263358 -259.973826)
		(end 273.421094 -259.973826)
		(width 0.18288)
		(layer "In11.Cu")
		(net "M_D_CPU0_SA_CA<4>")
	)
	(segment
		(start 295.59631 -258.941062)
		(end 293.751762 -258.941062)
		(width 0.18288)
		(layer "In11.Cu")
		(net "M_D_CPU0_SA_CA<4>")
	)
	(segment
		(start 344.936064 -256.03708)
		(end 344.921332 -256.045716)
		(width 0.088646)
		(layer "In11.Cu")
		(net "M_D_CPU0_SA_CA<4>")
	)
	(segment
		(start 343.996264 -256.03708)
		(end 343.981532 -256.045716)
		(width 0.088646)
		(layer "In11.Cu")
		(net "M_D_CPU0_SA_CA<4>")
	)
	(segment
		(start 291.234876 -258.089908)
		(end 290.214558 -259.110226)
		(width 0.18288)
		(layer "In11.Cu")
		(net "M_D_CPU0_SA_CA<4>")
	)
	(segment
		(start 342.116918 -256.03708)
		(end 342.106504 -256.043176)
		(width 0.088646)
		(layer "In11.Cu")
		(net "M_D_CPU0_SA_CA<4>")
	)
	(segment
		(start 315.337444 -256.620264)
		(end 313.838336 -257.240786)
		(width 0.18288)
		(layer "In11.Cu")
		(net "M_D_CPU0_SA_CA<4>")
	)
	(segment
		(start 277.806912 -258.089908)
		(end 276.147276 -258.089908)
		(width 0.18288)
		(layer "In11.Cu")
		(net "M_D_CPU0_SA_CA<4>")
	)
	(segment
		(start 265.199368 -263.236964)
		(end 264.729214 -262.76681)
		(width 0.18288)
		(layer "In11.Cu")
		(net "M_D_CPU0_SA_CA<4>")
	)
	(segment
		(start 273.421094 -259.973826)
		(end 272.608294 -260.786626)
		(width 0.18288)
		(layer "In11.Cu")
		(net "M_D_CPU0_SA_CA<4>")
	)
	(segment
		(start 283.691076 -258.089908)
		(end 282.46324 -259.317744)
		(width 0.18288)
		(layer "In11.Cu")
		(net "M_D_CPU0_SA_CA<4>")
	)
	(segment
		(start 307.532024 -258.031996)
		(end 307.088794 -258.475226)
		(width 0.18288)
		(layer "In11.Cu")
		(net "M_D_CPU0_SA_CA<4>")
	)
	(segment
		(start 285.73222 -258.425696)
		(end 285.396432 -258.089908)
		(width 0.18288)
		(layer "In11.Cu")
		(net "M_D_CPU0_SA_CA<4>")
	)
	(segment
		(start 313.838336 -257.240786)
		(end 313.19851 -257.880612)
		(width 0.18288)
		(layer "In11.Cu")
		(net "M_D_CPU0_SA_CA<4>")
	)
	(segment
		(start 343.056464 -256.03708)
		(end 343.04605 -256.043176)
		(width 0.088646)
		(layer "In11.Cu")
		(net "M_D_CPU0_SA_CA<4>")
	)
	(segment
		(start 280.4541 -259.317744)
		(end 280.077672 -258.941316)
		(width 0.18288)
		(layer "In11.Cu")
		(net "M_D_CPU0_SA_CA<4>")
	)
	(segment
		(start 272.608294 -260.786626)
		(end 271.954498 -260.786626)
		(width 0.18288)
		(layer "In11.Cu")
		(net "M_D_CPU0_SA_CA<4>")
	)
	(segment
		(start 290.214558 -259.110226)
		(end 285.93542 -259.110226)
		(width 0.18288)
		(layer "In11.Cu")
		(net "M_D_CPU0_SA_CA<4>")
	)
	(segment
		(start 313.19851 -257.880612)
		(end 307.89753 -257.880612)
		(width 0.18288)
		(layer "In11.Cu")
		(net "M_D_CPU0_SA_CA<4>")
	)
	(segment
		(start 331.45222 -256.108708)
		(end 330.927202 -256.108708)
		(width 0.088646)
		(layer "In11.Cu")
		(net "M_D_CPU0_SA_CA<4>")
	)
	(segment
		(start 285.93542 -259.110226)
		(end 285.73222 -258.907026)
		(width 0.18288)
		(layer "In11.Cu")
		(net "M_D_CPU0_SA_CA<4>")
	)
	(segment
		(start 328.921872 -256.108708)
		(end 328.410316 -256.620264)
		(width 0.18288)
		(layer "In11.Cu")
		(net "M_D_CPU0_SA_CA<4>")
	)
	(segment
		(start 278.65832 -258.941316)
		(end 277.806912 -258.089908)
		(width 0.18288)
		(layer "In11.Cu")
		(net "M_D_CPU0_SA_CA<4>")
	)
	(segment
		(start 330.927202 -256.108708)
		(end 328.921872 -256.108708)
		(width 0.18288)
		(layer "In11.Cu")
		(net "M_D_CPU0_SA_CA<4>")
	)
	(segment
		(start 269.270734 -262.450072)
		(end 269.16253 -262.341868)
		(width 0.18288)
		(layer "In11.Cu")
		(net "M_D_CPU0_SA_CA<4>")
	)
	(segment
		(start 301.328074 -258.994656)
		(end 300.423326 -258.089908)
		(width 0.18288)
		(layer "In11.Cu")
		(net "M_D_CPU0_SA_CA<4>")
	)
	(segment
		(start 331.966062 -255.986534)
		(end 331.574394 -255.986534)
		(width 0.088646)
		(layer "In11.Cu")
		(net "M_D_CPU0_SA_CA<4>")
	)
	(segment
		(start 337.417664 -256.03708)
		(end 337.402932 -256.045716)
		(width 0.088646)
		(layer "In11.Cu")
		(net "M_D_CPU0_SA_CA<4>")
	)
	(segment
		(start 282.46324 -259.317744)
		(end 280.4541 -259.317744)
		(width 0.18288)
		(layer "In11.Cu")
		(net "M_D_CPU0_SA_CA<4>")
	)
	(segment
		(start 271.954498 -260.786626)
		(end 270.291052 -262.450072)
		(width 0.18288)
		(layer "In11.Cu")
		(net "M_D_CPU0_SA_CA<4>")
	)
	(segment
		(start 267.60805 -263.236964)
		(end 265.199368 -263.236964)
		(width 0.18288)
		(layer "In11.Cu")
		(net "M_D_CPU0_SA_CA<4>")
	)
	(segment
		(start 297.79087 -259.077714)
		(end 295.732962 -259.077714)
		(width 0.18288)
		(layer "In11.Cu")
		(net "M_D_CPU0_SA_CA<4>")
	)
	(segment
		(start 285.73222 -258.907026)
		(end 285.73222 -258.425696)
		(width 0.18288)
		(layer "In11.Cu")
		(net "M_D_CPU0_SA_CA<4>")
	)
	(segment
		(start 300.423326 -258.089908)
		(end 298.778676 -258.089908)
		(width 0.18288)
		(layer "In11.Cu")
		(net "M_D_CPU0_SA_CA<4>")
	)
	(segment
		(start 285.396432 -258.089908)
		(end 283.691076 -258.089908)
		(width 0.18288)
		(layer "In11.Cu")
		(net "M_D_CPU0_SA_CA<4>")
	)
	(segment
		(start 307.088794 -258.703826)
		(end 306.797964 -258.994656)
		(width 0.18288)
		(layer "In11.Cu")
		(net "M_D_CPU0_SA_CA<4>")
	)
	(arc
		(start 332.718664 -256.03708)
		(mid 332.435962 -256.112856)
		(end 332.15326 -256.03708)
		(width 0.088646)
		(layer "In11.Cu")
		(net "M_D_CPU0_SA_CA<4>")
	)
	(arc
		(start 336.85226 -256.03708)
		(mid 336.665062 -255.986937)
		(end 336.477864 -256.03708)
		(width 0.088646)
		(layer "In11.Cu")
		(net "M_D_CPU0_SA_CA<4>")
	)
	(arc
		(start 336.477864 -256.03708)
		(mid 336.195162 -256.112856)
		(end 335.91246 -256.03708)
		(width 0.088646)
		(layer "In11.Cu")
		(net "M_D_CPU0_SA_CA<4>")
	)
	(arc
		(start 342.106504 -256.043176)
		(mid 341.828072 -256.113022)
		(end 341.55126 -256.03708)
		(width 0.088646)
		(layer "In11.Cu")
		(net "M_D_CPU0_SA_CA<4>")
	)
	(arc
		(start 334.97266 -256.03708)
		(mid 334.785462 -255.986937)
		(end 334.598264 -256.03708)
		(width 0.088646)
		(layer "In11.Cu")
		(net "M_D_CPU0_SA_CA<4>")
	)
	(arc
		(start 333.658464 -256.03708)
		(mid 333.375762 -256.112856)
		(end 333.09306 -256.03708)
		(width 0.088646)
		(layer "In11.Cu")
		(net "M_D_CPU0_SA_CA<4>")
	)
	(arc
		(start 339.282532 -256.045716)
		(mid 339.006057 -256.113036)
		(end 338.73186 -256.03708)
		(width 0.088646)
		(layer "In11.Cu")
		(net "M_D_CPU0_SA_CA<4>")
	)
	(arc
		(start 343.981532 -256.045716)
		(mid 343.705057 -256.113036)
		(end 343.43086 -256.03708)
		(width 0.088646)
		(layer "In11.Cu")
		(net "M_D_CPU0_SA_CA<4>")
	)
	(arc
		(start 338.73186 -256.03708)
		(mid 338.544662 -255.986937)
		(end 338.357464 -256.03708)
		(width 0.088646)
		(layer "In11.Cu")
		(net "M_D_CPU0_SA_CA<4>")
	)
	(arc
		(start 341.55126 -256.03708)
		(mid 341.364062 -255.986937)
		(end 341.176864 -256.03708)
		(width 0.088646)
		(layer "In11.Cu")
		(net "M_D_CPU0_SA_CA<4>")
	)
	(arc
		(start 333.09306 -256.03708)
		(mid 332.905862 -255.986937)
		(end 332.718664 -256.03708)
		(width 0.088646)
		(layer "In11.Cu")
		(net "M_D_CPU0_SA_CA<4>")
	)
	(arc
		(start 332.15326 -256.03708)
		(mid 332.062988 -255.999481)
		(end 331.966062 -255.986534)
		(width 0.088646)
		(layer "In11.Cu")
		(net "M_D_CPU0_SA_CA<4>")
	)
	(arc
		(start 344.37066 -256.03708)
		(mid 344.183462 -255.986937)
		(end 343.996264 -256.03708)
		(width 0.088646)
		(layer "In11.Cu")
		(net "M_D_CPU0_SA_CA<4>")
	)
	(arc
		(start 335.91246 -256.03708)
		(mid 335.725262 -255.986937)
		(end 335.538064 -256.03708)
		(width 0.088646)
		(layer "In11.Cu")
		(net "M_D_CPU0_SA_CA<4>")
	)
	(arc
		(start 343.04605 -256.043176)
		(mid 342.767872 -256.112899)
		(end 342.491314 -256.03708)
		(width 0.088646)
		(layer "In11.Cu")
		(net "M_D_CPU0_SA_CA<4>")
	)
	(arc
		(start 345.31046 -256.03708)
		(mid 345.123262 -255.986937)
		(end 344.936064 -256.03708)
		(width 0.088646)
		(layer "In11.Cu")
		(net "M_D_CPU0_SA_CA<4>")
	)
	(arc
		(start 342.491314 -256.03708)
		(mid 342.304116 -255.986937)
		(end 342.116918 -256.03708)
		(width 0.088646)
		(layer "In11.Cu")
		(net "M_D_CPU0_SA_CA<4>")
	)
	(arc
		(start 337.79206 -256.03708)
		(mid 337.604862 -255.986937)
		(end 337.417664 -256.03708)
		(width 0.088646)
		(layer "In11.Cu")
		(net "M_D_CPU0_SA_CA<4>")
	)
	(arc
		(start 337.402932 -256.045716)
		(mid 337.126457 -256.113036)
		(end 336.85226 -256.03708)
		(width 0.088646)
		(layer "In11.Cu")
		(net "M_D_CPU0_SA_CA<4>")
	)
	(arc
		(start 344.921332 -256.045716)
		(mid 344.644857 -256.113036)
		(end 344.37066 -256.03708)
		(width 0.088646)
		(layer "In11.Cu")
		(net "M_D_CPU0_SA_CA<4>")
	)
	(arc
		(start 339.67166 -256.03708)
		(mid 339.484462 -255.986937)
		(end 339.297264 -256.03708)
		(width 0.088646)
		(layer "In11.Cu")
		(net "M_D_CPU0_SA_CA<4>")
	)
	(arc
		(start 338.357464 -256.03708)
		(mid 338.074762 -256.112856)
		(end 337.79206 -256.03708)
		(width 0.088646)
		(layer "In11.Cu")
		(net "M_D_CPU0_SA_CA<4>")
	)
	(arc
		(start 341.162132 -256.045716)
		(mid 340.885657 -256.113036)
		(end 340.61146 -256.03708)
		(width 0.088646)
		(layer "In11.Cu")
		(net "M_D_CPU0_SA_CA<4>")
	)
	(arc
		(start 340.237064 -256.03708)
		(mid 339.954362 -256.112856)
		(end 339.67166 -256.03708)
		(width 0.088646)
		(layer "In11.Cu")
		(net "M_D_CPU0_SA_CA<4>")
	)
	(arc
		(start 345.861132 -256.045716)
		(mid 345.584657 -256.113036)
		(end 345.31046 -256.03708)
		(width 0.088646)
		(layer "In11.Cu")
		(net "M_D_CPU0_SA_CA<4>")
	)
	(arc
		(start 346.25026 -256.03708)
		(mid 346.063062 -255.986937)
		(end 345.875864 -256.03708)
		(width 0.088646)
		(layer "In11.Cu")
		(net "M_D_CPU0_SA_CA<4>")
	)
	(arc
		(start 347.002862 -256.361438)
		(mid 346.632307 -256.230368)
		(end 346.28074 -256.054606)
		(width 0.088646)
		(layer "In11.Cu")
		(net "M_D_CPU0_SA_CA<4>")
	)
	(arc
		(start 343.43086 -256.03708)
		(mid 343.243662 -255.986937)
		(end 343.056464 -256.03708)
		(width 0.088646)
		(layer "In11.Cu")
		(net "M_D_CPU0_SA_CA<4>")
	)
	(arc
		(start 334.03286 -256.03708)
		(mid 333.845662 -255.986937)
		(end 333.658464 -256.03708)
		(width 0.088646)
		(layer "In11.Cu")
		(net "M_D_CPU0_SA_CA<4>")
	)
	(arc
		(start 334.598264 -256.03708)
		(mid 334.315562 -256.112856)
		(end 334.03286 -256.03708)
		(width 0.088646)
		(layer "In11.Cu")
		(net "M_D_CPU0_SA_CA<4>")
	)
	(arc
		(start 340.61146 -256.03708)
		(mid 340.424262 -255.986937)
		(end 340.237064 -256.03708)
		(width 0.088646)
		(layer "In11.Cu")
		(net "M_D_CPU0_SA_CA<4>")
	)
	(arc
		(start 335.538064 -256.03708)
		(mid 335.255362 -256.112856)
		(end 334.97266 -256.03708)
		(width 0.088646)
		(layer "In11.Cu")
		(net "M_D_CPU0_SA_CA<4>")
	)
	(segment
		(start 265.369548 -264.041636)
		(end 264.825226 -264.041636)
		(width 0.20066)
		(layer "F.Cu")
		(net "M_D_CPU0_SA_CA<3>")
	)
	(segment
		(start 268.829282 -263.616694)
		(end 267.724382 -263.616694)
		(width 0.20066)
		(layer "F.Cu")
		(net "M_D_CPU0_SA_CA<3>")
	)
	(segment
		(start 262.003794 -263.913366)
		(end 262.003794 -263.742678)
		(width 0.20066)
		(layer "F.Cu")
		(net "M_D_CPU0_SA_CA<3>")
	)
	(segment
		(start 265.518646 -263.892538)
		(end 265.369548 -264.041636)
		(width 0.20066)
		(layer "F.Cu")
		(net "M_D_CPU0_SA_CA<3>")
	)
	(segment
		(start 266.700762 -263.824212)
		(end 266.25423 -263.824212)
		(width 0.20066)
		(layer "F.Cu")
		(net "M_D_CPU0_SA_CA<3>")
	)
	(segment
		(start 261.87781 -263.616694)
		(end 260.180582 -263.616694)
		(width 0.20066)
		(layer "F.Cu")
		(net "M_D_CPU0_SA_CA<3>")
	)
	(segment
		(start 264.825226 -264.041636)
		(end 262.752332 -264.041636)
		(width 0.1016)
		(layer "F.Cu")
		(net "M_D_CPU0_SA_CA<3>")
	)
	(segment
		(start 265.64717 -263.612376)
		(end 265.518646 -263.7409)
		(width 0.20066)
		(layer "F.Cu")
		(net "M_D_CPU0_SA_CA<3>")
	)
	(segment
		(start 262.50011 -264.05586)
		(end 262.146288 -264.05586)
		(width 0.20066)
		(layer "F.Cu")
		(net "M_D_CPU0_SA_CA<3>")
	)
	(segment
		(start 262.514334 -264.041636)
		(end 262.50011 -264.05586)
		(width 0.101854)
		(layer "F.Cu")
		(net "M_D_CPU0_SA_CA<3>")
	)
	(segment
		(start 262.146288 -264.05586)
		(end 262.003794 -263.913366)
		(width 0.20066)
		(layer "F.Cu")
		(net "M_D_CPU0_SA_CA<3>")
	)
	(segment
		(start 266.25423 -263.824212)
		(end 266.042394 -263.612376)
		(width 0.20066)
		(layer "F.Cu")
		(net "M_D_CPU0_SA_CA<3>")
	)
	(segment
		(start 266.90828 -263.616694)
		(end 266.700762 -263.824212)
		(width 0.20066)
		(layer "F.Cu")
		(net "M_D_CPU0_SA_CA<3>")
	)
	(segment
		(start 348.412562 -257.175)
		(end 348.412816 -257.175254)
		(width 0.20066)
		(layer "F.Cu")
		(net "M_D_CPU0_SA_CA<3>")
	)
	(segment
		(start 267.724382 -263.616694)
		(end 266.90828 -263.616694)
		(width 0.20066)
		(layer "F.Cu")
		(net "M_D_CPU0_SA_CA<3>")
	)
	(segment
		(start 265.518646 -263.7409)
		(end 265.518646 -263.892538)
		(width 0.20066)
		(layer "F.Cu")
		(net "M_D_CPU0_SA_CA<3>")
	)
	(segment
		(start 262.752332 -264.041636)
		(end 262.514334 -264.041636)
		(width 0.101854)
		(layer "F.Cu")
		(net "M_D_CPU0_SA_CA<3>")
	)
	(segment
		(start 262.003794 -263.742678)
		(end 261.87781 -263.616694)
		(width 0.20066)
		(layer "F.Cu")
		(net "M_D_CPU0_SA_CA<3>")
	)
	(segment
		(start 348.412562 -256.639314)
		(end 348.412562 -257.175)
		(width 0.20066)
		(layer "F.Cu")
		(net "M_D_CPU0_SA_CA<3>")
	)
	(segment
		(start 266.042394 -263.612376)
		(end 265.64717 -263.612376)
		(width 0.20066)
		(layer "F.Cu")
		(net "M_D_CPU0_SA_CA<3>")
	)
	(segment
		(start 331.497686 -256.468118)
		(end 330.927202 -256.468118)
		(width 0.088646)
		(layer "In11.Cu")
		(net "M_D_CPU0_SA_CA<3>")
	)
	(segment
		(start 346.815664 -256.685796)
		(end 346.800932 -256.67716)
		(width 0.088646)
		(layer "In11.Cu")
		(net "M_D_CPU0_SA_CA<3>")
	)
	(segment
		(start 331.76591 -256.736342)
		(end 331.497686 -256.468118)
		(width 0.088646)
		(layer "In11.Cu")
		(net "M_D_CPU0_SA_CA<3>")
	)
	(segment
		(start 314.22467 -257.762756)
		(end 313.596274 -258.391152)
		(width 0.18288)
		(layer "In11.Cu")
		(net "M_D_CPU0_SA_CA<3>")
	)
	(segment
		(start 315.52388 -257.225038)
		(end 314.22467 -257.762756)
		(width 0.18288)
		(layer "In11.Cu")
		(net "M_D_CPU0_SA_CA<3>")
	)
	(segment
		(start 344.936064 -256.685796)
		(end 344.921332 -256.67716)
		(width 0.088646)
		(layer "In11.Cu")
		(net "M_D_CPU0_SA_CA<3>")
	)
	(segment
		(start 313.596274 -258.391152)
		(end 312.76163 -258.391152)
		(width 0.18288)
		(layer "In11.Cu")
		(net "M_D_CPU0_SA_CA<3>")
	)
	(segment
		(start 275.294344 -259.698998)
		(end 275.294344 -260.080252)
		(width 0.18288)
		(layer "In11.Cu")
		(net "M_D_CPU0_SA_CA<3>")
	)
	(segment
		(start 319.442592 -257.225038)
		(end 315.52388 -257.225038)
		(width 0.18288)
		(layer "In11.Cu")
		(net "M_D_CPU0_SA_CA<3>")
	)
	(segment
		(start 276.051772 -258.94157)
		(end 275.294344 -259.698998)
		(width 0.18288)
		(layer "In11.Cu")
		(net "M_D_CPU0_SA_CA<3>")
	)
	(segment
		(start 342.116918 -256.685796)
		(end 342.106504 -256.6797)
		(width 0.088646)
		(layer "In11.Cu")
		(net "M_D_CPU0_SA_CA<3>")
	)
	(segment
		(start 340.237064 -256.685796)
		(end 340.222332 -256.67716)
		(width 0.088646)
		(layer "In11.Cu")
		(net "M_D_CPU0_SA_CA<3>")
	)
	(segment
		(start 274.84197 -260.532626)
		(end 273.598894 -260.532626)
		(width 0.18288)
		(layer "In11.Cu")
		(net "M_D_CPU0_SA_CA<3>")
	)
	(segment
		(start 290.332668 -259.7912)
		(end 288.353754 -259.7912)
		(width 0.18288)
		(layer "In11.Cu")
		(net "M_D_CPU0_SA_CA<3>")
	)
	(segment
		(start 285.245302 -259.643626)
		(end 284.542738 -258.941062)
		(width 0.18288)
		(layer "In11.Cu")
		(net "M_D_CPU0_SA_CA<3>")
	)
	(segment
		(start 347.847666 -256.739644)
		(end 347.755464 -256.685796)
		(width 0.088646)
		(layer "In11.Cu")
		(net "M_D_CPU0_SA_CA<3>")
	)
	(segment
		(start 273.598894 -260.532626)
		(end 272.712434 -261.419086)
		(width 0.18288)
		(layer "In11.Cu")
		(net "M_D_CPU0_SA_CA<3>")
	)
	(segment
		(start 329.051158 -256.468118)
		(end 328.553572 -256.965704)
		(width 0.18288)
		(layer "In11.Cu")
		(net "M_D_CPU0_SA_CA<3>")
	)
	(segment
		(start 279.055068 -259.7912)
		(end 278.831294 -259.567426)
		(width 0.18288)
		(layer "In11.Cu")
		(net "M_D_CPU0_SA_CA<3>")
	)
	(segment
		(start 301.663354 -259.727446)
		(end 301.663354 -259.872734)
		(width 0.18288)
		(layer "In11.Cu")
		(net "M_D_CPU0_SA_CA<3>")
	)
	(segment
		(start 300.945296 -259.576824)
		(end 300.582584 -259.214112)
		(width 0.18288)
		(layer "In11.Cu")
		(net "M_D_CPU0_SA_CA<3>")
	)
	(segment
		(start 343.056464 -256.685796)
		(end 343.04605 -256.6797)
		(width 0.088646)
		(layer "In11.Cu")
		(net "M_D_CPU0_SA_CA<3>")
	)
	(segment
		(start 278.831294 -259.567426)
		(end 277.612094 -259.567426)
		(width 0.18288)
		(layer "In11.Cu")
		(net "M_D_CPU0_SA_CA<3>")
	)
	(segment
		(start 300.582584 -259.214112)
		(end 299.833538 -259.214112)
		(width 0.18288)
		(layer "In11.Cu")
		(net "M_D_CPU0_SA_CA<3>")
	)
	(segment
		(start 283.585412 -258.941062)
		(end 282.622244 -259.90423)
		(width 0.18288)
		(layer "In11.Cu")
		(net "M_D_CPU0_SA_CA<3>")
	)
	(segment
		(start 282.622244 -259.90423)
		(end 280.241756 -259.90423)
		(width 0.18288)
		(layer "In11.Cu")
		(net "M_D_CPU0_SA_CA<3>")
	)
	(segment
		(start 269.47495 -262.971026)
		(end 268.829282 -263.616694)
		(width 0.18288)
		(layer "In11.Cu")
		(net "M_D_CPU0_SA_CA<3>")
	)
	(segment
		(start 297.817286 -259.7912)
		(end 292.937438 -259.7912)
		(width 0.18288)
		(layer "In11.Cu")
		(net "M_D_CPU0_SA_CA<3>")
	)
	(segment
		(start 280.128726 -259.7912)
		(end 279.055068 -259.7912)
		(width 0.18288)
		(layer "In11.Cu")
		(net "M_D_CPU0_SA_CA<3>")
	)
	(segment
		(start 298.665646 -258.94284)
		(end 297.817286 -259.7912)
		(width 0.18288)
		(layer "In11.Cu")
		(net "M_D_CPU0_SA_CA<3>")
	)
	(segment
		(start 307.58765 -258.98221)
		(end 307.002434 -259.567426)
		(width 0.18288)
		(layer "In11.Cu")
		(net "M_D_CPU0_SA_CA<3>")
	)
	(segment
		(start 301.823374 -259.567426)
		(end 301.663354 -259.727446)
		(width 0.18288)
		(layer "In11.Cu")
		(net "M_D_CPU0_SA_CA<3>")
	)
	(segment
		(start 328.553572 -256.965704)
		(end 319.701926 -256.965704)
		(width 0.18288)
		(layer "In11.Cu")
		(net "M_D_CPU0_SA_CA<3>")
	)
	(segment
		(start 292.087554 -258.941316)
		(end 291.182552 -258.941316)
		(width 0.18288)
		(layer "In11.Cu")
		(net "M_D_CPU0_SA_CA<3>")
	)
	(segment
		(start 307.002434 -259.567426)
		(end 301.823374 -259.567426)
		(width 0.18288)
		(layer "In11.Cu")
		(net "M_D_CPU0_SA_CA<3>")
	)
	(segment
		(start 299.833538 -259.214112)
		(end 299.562266 -258.94284)
		(width 0.18288)
		(layer "In11.Cu")
		(net "M_D_CPU0_SA_CA<3>")
	)
	(segment
		(start 288.353754 -259.7912)
		(end 288.20618 -259.643626)
		(width 0.18288)
		(layer "In11.Cu")
		(net "M_D_CPU0_SA_CA<3>")
	)
	(segment
		(start 312.069226 -258.98221)
		(end 307.58765 -258.98221)
		(width 0.18288)
		(layer "In11.Cu")
		(net "M_D_CPU0_SA_CA<3>")
	)
	(segment
		(start 270.550894 -262.971026)
		(end 269.47495 -262.971026)
		(width 0.18288)
		(layer "In11.Cu")
		(net "M_D_CPU0_SA_CA<3>")
	)
	(segment
		(start 280.241756 -259.90423)
		(end 280.128726 -259.7912)
		(width 0.18288)
		(layer "In11.Cu")
		(net "M_D_CPU0_SA_CA<3>")
	)
	(segment
		(start 299.562266 -258.94284)
		(end 298.665646 -258.94284)
		(width 0.18288)
		(layer "In11.Cu")
		(net "M_D_CPU0_SA_CA<3>")
	)
	(segment
		(start 288.20618 -259.643626)
		(end 285.245302 -259.643626)
		(width 0.18288)
		(layer "In11.Cu")
		(net "M_D_CPU0_SA_CA<3>")
	)
	(segment
		(start 277.612094 -259.567426)
		(end 276.986238 -258.94157)
		(width 0.18288)
		(layer "In11.Cu")
		(net "M_D_CPU0_SA_CA<3>")
	)
	(segment
		(start 330.927202 -256.468118)
		(end 329.051158 -256.468118)
		(width 0.18288)
		(layer "In11.Cu")
		(net "M_D_CPU0_SA_CA<3>")
	)
	(segment
		(start 301.503334 -260.032754)
		(end 301.155354 -260.032754)
		(width 0.18288)
		(layer "In11.Cu")
		(net "M_D_CPU0_SA_CA<3>")
	)
	(segment
		(start 275.294344 -260.080252)
		(end 274.84197 -260.532626)
		(width 0.18288)
		(layer "In11.Cu")
		(net "M_D_CPU0_SA_CA<3>")
	)
	(segment
		(start 343.996264 -256.685796)
		(end 343.981532 -256.67716)
		(width 0.088646)
		(layer "In11.Cu")
		(net "M_D_CPU0_SA_CA<3>")
	)
	(segment
		(start 301.663354 -259.872734)
		(end 301.503334 -260.032754)
		(width 0.18288)
		(layer "In11.Cu")
		(net "M_D_CPU0_SA_CA<3>")
	)
	(segment
		(start 272.102834 -261.419086)
		(end 270.550894 -262.971026)
		(width 0.18288)
		(layer "In11.Cu")
		(net "M_D_CPU0_SA_CA<3>")
	)
	(segment
		(start 312.76163 -258.391152)
		(end 312.588656 -258.46278)
		(width 0.18288)
		(layer "In11.Cu")
		(net "M_D_CPU0_SA_CA<3>")
	)
	(segment
		(start 300.945296 -259.822696)
		(end 300.945296 -259.576824)
		(width 0.18288)
		(layer "In11.Cu")
		(net "M_D_CPU0_SA_CA<3>")
	)
	(segment
		(start 312.588656 -258.46278)
		(end 312.069226 -258.98221)
		(width 0.18288)
		(layer "In11.Cu")
		(net "M_D_CPU0_SA_CA<3>")
	)
	(segment
		(start 301.155354 -260.032754)
		(end 300.945296 -259.822696)
		(width 0.18288)
		(layer "In11.Cu")
		(net "M_D_CPU0_SA_CA<3>")
	)
	(segment
		(start 272.712434 -261.419086)
		(end 272.102834 -261.419086)
		(width 0.18288)
		(layer "In11.Cu")
		(net "M_D_CPU0_SA_CA<3>")
	)
	(segment
		(start 276.986238 -258.94157)
		(end 276.051772 -258.94157)
		(width 0.18288)
		(layer "In11.Cu")
		(net "M_D_CPU0_SA_CA<3>")
	)
	(segment
		(start 292.937438 -259.7912)
		(end 292.087554 -258.941316)
		(width 0.18288)
		(layer "In11.Cu")
		(net "M_D_CPU0_SA_CA<3>")
	)
	(segment
		(start 284.542738 -258.941062)
		(end 283.585412 -258.941062)
		(width 0.18288)
		(layer "In11.Cu")
		(net "M_D_CPU0_SA_CA<3>")
	)
	(segment
		(start 291.182552 -258.941316)
		(end 290.332668 -259.7912)
		(width 0.18288)
		(layer "In11.Cu")
		(net "M_D_CPU0_SA_CA<3>")
	)
	(segment
		(start 319.701926 -256.965704)
		(end 319.442592 -257.225038)
		(width 0.18288)
		(layer "In11.Cu")
		(net "M_D_CPU0_SA_CA<3>")
	)
	(segment
		(start 331.966062 -256.736342)
		(end 331.76591 -256.736342)
		(width 0.088646)
		(layer "In11.Cu")
		(net "M_D_CPU0_SA_CA<3>")
	)
	(arc
		(start 334.97266 -256.685796)
		(mid 334.785462 -256.735939)
		(end 334.598264 -256.685796)
		(width 0.088646)
		(layer "In11.Cu")
		(net "M_D_CPU0_SA_CA<3>")
	)
	(arc
		(start 334.598264 -256.685796)
		(mid 334.315562 -256.61002)
		(end 334.03286 -256.685796)
		(width 0.088646)
		(layer "In11.Cu")
		(net "M_D_CPU0_SA_CA<3>")
	)
	(arc
		(start 342.491314 -256.685796)
		(mid 342.304116 -256.735939)
		(end 342.116918 -256.685796)
		(width 0.088646)
		(layer "In11.Cu")
		(net "M_D_CPU0_SA_CA<3>")
	)
	(arc
		(start 337.79206 -256.685796)
		(mid 337.604862 -256.735939)
		(end 337.417664 -256.685796)
		(width 0.088646)
		(layer "In11.Cu")
		(net "M_D_CPU0_SA_CA<3>")
	)
	(arc
		(start 335.538064 -256.685796)
		(mid 335.255362 -256.61002)
		(end 334.97266 -256.685796)
		(width 0.088646)
		(layer "In11.Cu")
		(net "M_D_CPU0_SA_CA<3>")
	)
	(arc
		(start 333.658464 -256.685796)
		(mid 333.375762 -256.61002)
		(end 333.09306 -256.685796)
		(width 0.088646)
		(layer "In11.Cu")
		(net "M_D_CPU0_SA_CA<3>")
	)
	(arc
		(start 346.800932 -256.67716)
		(mid 346.524457 -256.60984)
		(end 346.25026 -256.685796)
		(width 0.088646)
		(layer "In11.Cu")
		(net "M_D_CPU0_SA_CA<3>")
	)
	(arc
		(start 339.297264 -256.685796)
		(mid 339.014562 -256.61002)
		(end 338.73186 -256.685796)
		(width 0.088646)
		(layer "In11.Cu")
		(net "M_D_CPU0_SA_CA<3>")
	)
	(arc
		(start 344.921332 -256.67716)
		(mid 344.644857 -256.60984)
		(end 344.37066 -256.685796)
		(width 0.088646)
		(layer "In11.Cu")
		(net "M_D_CPU0_SA_CA<3>")
	)
	(arc
		(start 334.03286 -256.685796)
		(mid 333.845662 -256.735939)
		(end 333.658464 -256.685796)
		(width 0.088646)
		(layer "In11.Cu")
		(net "M_D_CPU0_SA_CA<3>")
	)
	(arc
		(start 339.67166 -256.685796)
		(mid 339.484462 -256.735939)
		(end 339.297264 -256.685796)
		(width 0.088646)
		(layer "In11.Cu")
		(net "M_D_CPU0_SA_CA<3>")
	)
	(arc
		(start 332.718664 -256.685796)
		(mid 332.435962 -256.61002)
		(end 332.15326 -256.685796)
		(width 0.088646)
		(layer "In11.Cu")
		(net "M_D_CPU0_SA_CA<3>")
	)
	(arc
		(start 340.222332 -256.67716)
		(mid 339.945857 -256.60984)
		(end 339.67166 -256.685796)
		(width 0.088646)
		(layer "In11.Cu")
		(net "M_D_CPU0_SA_CA<3>")
	)
	(arc
		(start 347.755464 -256.685796)
		(mid 347.472762 -256.61002)
		(end 347.19006 -256.685796)
		(width 0.088646)
		(layer "In11.Cu")
		(net "M_D_CPU0_SA_CA<3>")
	)
	(arc
		(start 345.875864 -256.685796)
		(mid 345.593162 -256.61002)
		(end 345.31046 -256.685796)
		(width 0.088646)
		(layer "In11.Cu")
		(net "M_D_CPU0_SA_CA<3>")
	)
	(arc
		(start 337.417664 -256.685796)
		(mid 337.134962 -256.61002)
		(end 336.85226 -256.685796)
		(width 0.088646)
		(layer "In11.Cu")
		(net "M_D_CPU0_SA_CA<3>")
	)
	(arc
		(start 332.15326 -256.685796)
		(mid 332.062988 -256.723395)
		(end 331.966062 -256.736342)
		(width 0.088646)
		(layer "In11.Cu")
		(net "M_D_CPU0_SA_CA<3>")
	)
	(arc
		(start 336.477864 -256.685796)
		(mid 336.195162 -256.61002)
		(end 335.91246 -256.685796)
		(width 0.088646)
		(layer "In11.Cu")
		(net "M_D_CPU0_SA_CA<3>")
	)
	(arc
		(start 345.31046 -256.685796)
		(mid 345.123262 -256.735939)
		(end 344.936064 -256.685796)
		(width 0.088646)
		(layer "In11.Cu")
		(net "M_D_CPU0_SA_CA<3>")
	)
	(arc
		(start 342.106504 -256.6797)
		(mid 341.828072 -256.609854)
		(end 341.55126 -256.685796)
		(width 0.088646)
		(layer "In11.Cu")
		(net "M_D_CPU0_SA_CA<3>")
	)
	(arc
		(start 343.981532 -256.67716)
		(mid 343.705057 -256.60984)
		(end 343.43086 -256.685796)
		(width 0.088646)
		(layer "In11.Cu")
		(net "M_D_CPU0_SA_CA<3>")
	)
	(arc
		(start 336.85226 -256.685796)
		(mid 336.665062 -256.735939)
		(end 336.477864 -256.685796)
		(width 0.088646)
		(layer "In11.Cu")
		(net "M_D_CPU0_SA_CA<3>")
	)
	(arc
		(start 341.55126 -256.685796)
		(mid 341.364062 -256.735939)
		(end 341.176864 -256.685796)
		(width 0.088646)
		(layer "In11.Cu")
		(net "M_D_CPU0_SA_CA<3>")
	)
	(arc
		(start 335.91246 -256.685796)
		(mid 335.725262 -256.735939)
		(end 335.538064 -256.685796)
		(width 0.088646)
		(layer "In11.Cu")
		(net "M_D_CPU0_SA_CA<3>")
	)
	(arc
		(start 343.04605 -256.6797)
		(mid 342.767872 -256.609977)
		(end 342.491314 -256.685796)
		(width 0.088646)
		(layer "In11.Cu")
		(net "M_D_CPU0_SA_CA<3>")
	)
	(arc
		(start 346.25026 -256.685796)
		(mid 346.063062 -256.735939)
		(end 345.875864 -256.685796)
		(width 0.088646)
		(layer "In11.Cu")
		(net "M_D_CPU0_SA_CA<3>")
	)
	(arc
		(start 343.43086 -256.685796)
		(mid 343.243662 -256.735939)
		(end 343.056464 -256.685796)
		(width 0.088646)
		(layer "In11.Cu")
		(net "M_D_CPU0_SA_CA<3>")
	)
	(arc
		(start 344.37066 -256.685796)
		(mid 344.183462 -256.735939)
		(end 343.996264 -256.685796)
		(width 0.088646)
		(layer "In11.Cu")
		(net "M_D_CPU0_SA_CA<3>")
	)
	(arc
		(start 338.357464 -256.685796)
		(mid 338.074762 -256.61002)
		(end 337.79206 -256.685796)
		(width 0.088646)
		(layer "In11.Cu")
		(net "M_D_CPU0_SA_CA<3>")
	)
	(arc
		(start 333.09306 -256.685796)
		(mid 332.905862 -256.735939)
		(end 332.718664 -256.685796)
		(width 0.088646)
		(layer "In11.Cu")
		(net "M_D_CPU0_SA_CA<3>")
	)
	(arc
		(start 347.19006 -256.685796)
		(mid 347.002862 -256.735939)
		(end 346.815664 -256.685796)
		(width 0.088646)
		(layer "In11.Cu")
		(net "M_D_CPU0_SA_CA<3>")
	)
	(arc
		(start 338.73186 -256.685796)
		(mid 338.544662 -256.735939)
		(end 338.357464 -256.685796)
		(width 0.088646)
		(layer "In11.Cu")
		(net "M_D_CPU0_SA_CA<3>")
	)
	(arc
		(start 348.412816 -257.175254)
		(mid 348.144273 -256.939244)
		(end 347.847666 -256.739644)
		(width 0.088646)
		(layer "In11.Cu")
		(net "M_D_CPU0_SA_CA<3>")
	)
	(arc
		(start 341.176864 -256.685796)
		(mid 340.894162 -256.61002)
		(end 340.61146 -256.685796)
		(width 0.088646)
		(layer "In11.Cu")
		(net "M_D_CPU0_SA_CA<3>")
	)
	(arc
		(start 340.61146 -256.685796)
		(mid 340.424262 -256.735939)
		(end 340.237064 -256.685796)
		(width 0.088646)
		(layer "In11.Cu")
		(net "M_D_CPU0_SA_CA<3>")
	)
	(segment
		(start 259.065268 -264.041636)
		(end 259.056378 -264.032746)
		(width 0.1016)
		(layer "F.Cu")
		(net "M_D_CPU0_SA_CA<2>")
	)
	(segment
		(start 261.050786 -264.041636)
		(end 259.065268 -264.041636)
		(width 0.1016)
		(layer "F.Cu")
		(net "M_D_CPU0_SA_CA<2>")
	)
	(segment
		(start 258.28498 -264.195306)
		(end 258.28498 -264.523474)
		(width 0.20066)
		(layer "F.Cu")
		(net "M_D_CPU0_SA_CA<2>")
	)
	(segment
		(start 346.532962 -256.639314)
		(end 346.532962 -257.175)
		(width 0.20066)
		(layer "F.Cu")
		(net "M_D_CPU0_SA_CA<2>")
	)
	(segment
		(start 263.624314 -264.466578)
		(end 261.984998 -264.466578)
		(width 0.20066)
		(layer "F.Cu")
		(net "M_D_CPU0_SA_CA<2>")
	)
	(segment
		(start 257.414776 -264.466578)
		(end 256.080514 -264.466578)
		(width 0.20066)
		(layer "F.Cu")
		(net "M_D_CPU0_SA_CA<2>")
	)
	(segment
		(start 259.056378 -264.032746)
		(end 258.44754 -264.032746)
		(width 0.20066)
		(layer "F.Cu")
		(net "M_D_CPU0_SA_CA<2>")
	)
	(segment
		(start 261.984998 -264.466578)
		(end 261.560056 -264.041636)
		(width 0.20066)
		(layer "F.Cu")
		(net "M_D_CPU0_SA_CA<2>")
	)
	(segment
		(start 264.729214 -264.466578)
		(end 263.624314 -264.466578)
		(width 0.20066)
		(layer "F.Cu")
		(net "M_D_CPU0_SA_CA<2>")
	)
	(segment
		(start 346.532962 -257.175)
		(end 346.533216 -257.175254)
		(width 0.20066)
		(layer "F.Cu")
		(net "M_D_CPU0_SA_CA<2>")
	)
	(segment
		(start 261.381494 -264.041636)
		(end 261.050786 -264.041636)
		(width 0.101854)
		(layer "F.Cu")
		(net "M_D_CPU0_SA_CA<2>")
	)
	(segment
		(start 258.44754 -264.032746)
		(end 258.28498 -264.195306)
		(width 0.20066)
		(layer "F.Cu")
		(net "M_D_CPU0_SA_CA<2>")
	)
	(segment
		(start 261.560056 -264.041636)
		(end 261.381494 -264.041636)
		(width 0.20066)
		(layer "F.Cu")
		(net "M_D_CPU0_SA_CA<2>")
	)
	(segment
		(start 257.626104 -264.677906)
		(end 257.414776 -264.466578)
		(width 0.20066)
		(layer "F.Cu")
		(net "M_D_CPU0_SA_CA<2>")
	)
	(segment
		(start 258.28498 -264.523474)
		(end 258.130548 -264.677906)
		(width 0.20066)
		(layer "F.Cu")
		(net "M_D_CPU0_SA_CA<2>")
	)
	(segment
		(start 258.130548 -264.677906)
		(end 257.626104 -264.677906)
		(width 0.20066)
		(layer "F.Cu")
		(net "M_D_CPU0_SA_CA<2>")
	)
	(segment
		(start 273.580098 -261.599426)
		(end 272.675096 -262.504428)
		(width 0.18288)
		(layer "In11.Cu")
		(net "M_D_CPU0_SA_CA<2>")
	)
	(segment
		(start 308.638194 -260.081776)
		(end 308.638194 -259.717286)
		(width 0.18288)
		(layer "In11.Cu")
		(net "M_D_CPU0_SA_CA<2>")
	)
	(segment
		(start 307.213 -260.083808)
		(end 303.557178 -260.083808)
		(width 0.18288)
		(layer "In11.Cu")
		(net "M_D_CPU0_SA_CA<2>")
	)
	(segment
		(start 270.387572 -264.114026)
		(end 269.890494 -264.114026)
		(width 0.18288)
		(layer "In11.Cu")
		(net "M_D_CPU0_SA_CA<2>")
	)
	(segment
		(start 309.339234 -260.081776)
		(end 309.146194 -260.274816)
		(width 0.18288)
		(layer "In11.Cu")
		(net "M_D_CPU0_SA_CA<2>")
	)
	(segment
		(start 308.445154 -259.524246)
		(end 307.772562 -259.524246)
		(width 0.18288)
		(layer "In11.Cu")
		(net "M_D_CPU0_SA_CA<2>")
	)
	(segment
		(start 299.799502 -260.730492)
		(end 299.710094 -260.641084)
		(width 0.18288)
		(layer "In11.Cu")
		(net "M_D_CPU0_SA_CA<2>")
	)
	(segment
		(start 309.532274 -259.524246)
		(end 309.339234 -259.717286)
		(width 0.18288)
		(layer "In11.Cu")
		(net "M_D_CPU0_SA_CA<2>")
	)
	(segment
		(start 292.168326 -260.786626)
		(end 292.023038 -260.641338)
		(width 0.18288)
		(layer "In11.Cu")
		(net "M_D_CPU0_SA_CA<2>")
	)
	(segment
		(start 314.341002 -258.964938)
		(end 312.872882 -258.964938)
		(width 0.18288)
		(layer "In11.Cu")
		(net "M_D_CPU0_SA_CA<2>")
	)
	(segment
		(start 303.557178 -260.083808)
		(end 302.910494 -260.730492)
		(width 0.18288)
		(layer "In11.Cu")
		(net "M_D_CPU0_SA_CA<2>")
	)
	(segment
		(start 330.927202 -256.833878)
		(end 329.174094 -256.833878)
		(width 0.18288)
		(layer "In11.Cu")
		(net "M_D_CPU0_SA_CA<2>")
	)
	(segment
		(start 284.749494 -260.641084)
		(end 282.907994 -260.641084)
		(width 0.18288)
		(layer "In11.Cu")
		(net "M_D_CPU0_SA_CA<2>")
	)
	(segment
		(start 269.815564 -264.039096)
		(end 265.156696 -264.039096)
		(width 0.18288)
		(layer "In11.Cu")
		(net "M_D_CPU0_SA_CA<2>")
	)
	(segment
		(start 293.309294 -260.786626)
		(end 292.168326 -260.786626)
		(width 0.18288)
		(layer "In11.Cu")
		(net "M_D_CPU0_SA_CA<2>")
	)
	(segment
		(start 288.153094 -260.768592)
		(end 284.877002 -260.768592)
		(width 0.18288)
		(layer "In11.Cu")
		(net "M_D_CPU0_SA_CA<2>")
	)
	(segment
		(start 278.932894 -260.786626)
		(end 277.274274 -260.786626)
		(width 0.18288)
		(layer "In11.Cu")
		(net "M_D_CPU0_SA_CA<2>")
	)
	(segment
		(start 277.274274 -260.786626)
		(end 277.129494 -260.641846)
		(width 0.18288)
		(layer "In11.Cu")
		(net "M_D_CPU0_SA_CA<2>")
	)
	(segment
		(start 272.675096 -262.504428)
		(end 271.99717 -262.504428)
		(width 0.18288)
		(layer "In11.Cu")
		(net "M_D_CPU0_SA_CA<2>")
	)
	(segment
		(start 342.975946 -256.859532)
		(end 342.961214 -256.850896)
		(width 0.088646)
		(layer "In11.Cu")
		(net "M_D_CPU0_SA_CA<2>")
	)
	(segment
		(start 341.091774 -256.856992)
		(end 341.08136 -256.850896)
		(width 0.088646)
		(layer "In11.Cu")
		(net "M_D_CPU0_SA_CA<2>")
	)
	(segment
		(start 319.954402 -257.311144)
		(end 319.443608 -257.821938)
		(width 0.18288)
		(layer "In11.Cu")
		(net "M_D_CPU0_SA_CA<2>")
	)
	(segment
		(start 277.129494 -260.641846)
		(end 275.610828 -260.641846)
		(width 0.18288)
		(layer "In11.Cu")
		(net "M_D_CPU0_SA_CA<2>")
	)
	(segment
		(start 308.831234 -260.274816)
		(end 308.638194 -260.081776)
		(width 0.18288)
		(layer "In11.Cu")
		(net "M_D_CPU0_SA_CA<2>")
	)
	(segment
		(start 281.224736 -261.624826)
		(end 280.240994 -260.641084)
		(width 0.18288)
		(layer "In11.Cu")
		(net "M_D_CPU0_SA_CA<2>")
	)
	(segment
		(start 296.219626 -260.641084)
		(end 293.454836 -260.641084)
		(width 0.18288)
		(layer "In11.Cu")
		(net "M_D_CPU0_SA_CA<2>")
	)
	(segment
		(start 307.772562 -259.524246)
		(end 307.213 -260.083808)
		(width 0.18288)
		(layer "In11.Cu")
		(net "M_D_CPU0_SA_CA<2>")
	)
	(segment
		(start 296.320464 -260.540246)
		(end 296.219626 -260.641084)
		(width 0.18288)
		(layer "In11.Cu")
		(net "M_D_CPU0_SA_CA<2>")
	)
	(segment
		(start 331.966062 -256.926588)
		(end 331.600556 -256.926588)
		(width 0.088646)
		(layer "In11.Cu")
		(net "M_D_CPU0_SA_CA<2>")
	)
	(segment
		(start 302.910494 -260.730492)
		(end 299.799502 -260.730492)
		(width 0.18288)
		(layer "In11.Cu")
		(net "M_D_CPU0_SA_CA<2>")
	)
	(segment
		(start 275.610828 -260.641846)
		(end 274.653248 -261.599426)
		(width 0.18288)
		(layer "In11.Cu")
		(net "M_D_CPU0_SA_CA<2>")
	)
	(segment
		(start 343.915746 -256.859532)
		(end 343.901014 -256.850896)
		(width 0.088646)
		(layer "In11.Cu")
		(net "M_D_CPU0_SA_CA<2>")
	)
	(segment
		(start 312.313574 -259.524246)
		(end 309.532274 -259.524246)
		(width 0.18288)
		(layer "In11.Cu")
		(net "M_D_CPU0_SA_CA<2>")
	)
	(segment
		(start 288.51606 -260.405626)
		(end 288.153094 -260.768592)
		(width 0.18288)
		(layer "In11.Cu")
		(net "M_D_CPU0_SA_CA<2>")
	)
	(segment
		(start 319.443608 -257.821938)
		(end 315.484002 -257.821938)
		(width 0.18288)
		(layer "In11.Cu")
		(net "M_D_CPU0_SA_CA<2>")
	)
	(segment
		(start 271.99717 -262.504428)
		(end 270.387572 -264.114026)
		(width 0.18288)
		(layer "In11.Cu")
		(net "M_D_CPU0_SA_CA<2>")
	)
	(segment
		(start 279.078436 -260.641084)
		(end 278.932894 -260.786626)
		(width 0.18288)
		(layer "In11.Cu")
		(net "M_D_CPU0_SA_CA<2>")
	)
	(segment
		(start 309.146194 -260.274816)
		(end 308.831234 -260.274816)
		(width 0.18288)
		(layer "In11.Cu")
		(net "M_D_CPU0_SA_CA<2>")
	)
	(segment
		(start 331.600556 -256.926588)
		(end 331.507846 -256.833878)
		(width 0.088646)
		(layer "In11.Cu")
		(net "M_D_CPU0_SA_CA<2>")
	)
	(segment
		(start 274.653248 -261.599426)
		(end 273.580098 -261.599426)
		(width 0.18288)
		(layer "In11.Cu")
		(net "M_D_CPU0_SA_CA<2>")
	)
	(segment
		(start 281.924252 -261.624826)
		(end 281.224736 -261.624826)
		(width 0.18288)
		(layer "In11.Cu")
		(net "M_D_CPU0_SA_CA<2>")
	)
	(segment
		(start 265.156696 -264.039096)
		(end 264.729214 -264.466578)
		(width 0.18288)
		(layer "In11.Cu")
		(net "M_D_CPU0_SA_CA<2>")
	)
	(segment
		(start 309.339234 -259.717286)
		(end 309.339234 -260.081776)
		(width 0.18288)
		(layer "In11.Cu")
		(net "M_D_CPU0_SA_CA<2>")
	)
	(segment
		(start 299.710094 -260.641084)
		(end 297.633644 -260.641084)
		(width 0.18288)
		(layer "In11.Cu")
		(net "M_D_CPU0_SA_CA<2>")
	)
	(segment
		(start 312.872882 -258.964938)
		(end 312.313574 -259.524246)
		(width 0.18288)
		(layer "In11.Cu")
		(net "M_D_CPU0_SA_CA<2>")
	)
	(segment
		(start 331.507846 -256.833878)
		(end 330.927202 -256.833878)
		(width 0.088646)
		(layer "In11.Cu")
		(net "M_D_CPU0_SA_CA<2>")
	)
	(segment
		(start 282.907994 -260.641084)
		(end 281.924252 -261.624826)
		(width 0.18288)
		(layer "In11.Cu")
		(net "M_D_CPU0_SA_CA<2>")
	)
	(segment
		(start 315.484002 -257.821938)
		(end 314.341002 -258.964938)
		(width 0.18288)
		(layer "In11.Cu")
		(net "M_D_CPU0_SA_CA<2>")
	)
	(segment
		(start 340.152228 -256.856992)
		(end 340.141814 -256.850896)
		(width 0.088646)
		(layer "In11.Cu")
		(net "M_D_CPU0_SA_CA<2>")
	)
	(segment
		(start 329.174094 -256.833878)
		(end 328.696828 -257.311144)
		(width 0.18288)
		(layer "In11.Cu")
		(net "M_D_CPU0_SA_CA<2>")
	)
	(segment
		(start 292.023038 -260.641338)
		(end 290.011866 -260.641338)
		(width 0.18288)
		(layer "In11.Cu")
		(net "M_D_CPU0_SA_CA<2>")
	)
	(segment
		(start 339.212174 -256.856992)
		(end 339.20176 -256.850896)
		(width 0.088646)
		(layer "In11.Cu")
		(net "M_D_CPU0_SA_CA<2>")
	)
	(segment
		(start 269.890494 -264.114026)
		(end 269.815564 -264.039096)
		(width 0.18288)
		(layer "In11.Cu")
		(net "M_D_CPU0_SA_CA<2>")
	)
	(segment
		(start 280.240994 -260.641084)
		(end 279.078436 -260.641084)
		(width 0.18288)
		(layer "In11.Cu")
		(net "M_D_CPU0_SA_CA<2>")
	)
	(segment
		(start 289.776154 -260.405626)
		(end 288.51606 -260.405626)
		(width 0.18288)
		(layer "In11.Cu")
		(net "M_D_CPU0_SA_CA<2>")
	)
	(segment
		(start 293.454836 -260.641084)
		(end 293.309294 -260.786626)
		(width 0.18288)
		(layer "In11.Cu")
		(net "M_D_CPU0_SA_CA<2>")
	)
	(segment
		(start 297.633644 -260.641084)
		(end 297.532806 -260.540246)
		(width 0.18288)
		(layer "In11.Cu")
		(net "M_D_CPU0_SA_CA<2>")
	)
	(segment
		(start 297.532806 -260.540246)
		(end 296.320464 -260.540246)
		(width 0.18288)
		(layer "In11.Cu")
		(net "M_D_CPU0_SA_CA<2>")
	)
	(segment
		(start 344.851228 -256.856992)
		(end 344.840814 -256.850896)
		(width 0.088646)
		(layer "In11.Cu")
		(net "M_D_CPU0_SA_CA<2>")
	)
	(segment
		(start 328.696828 -257.311144)
		(end 319.954402 -257.311144)
		(width 0.18288)
		(layer "In11.Cu")
		(net "M_D_CPU0_SA_CA<2>")
	)
	(segment
		(start 308.638194 -259.717286)
		(end 308.445154 -259.524246)
		(width 0.18288)
		(layer "In11.Cu")
		(net "M_D_CPU0_SA_CA<2>")
	)
	(segment
		(start 290.011866 -260.641338)
		(end 289.776154 -260.405626)
		(width 0.18288)
		(layer "In11.Cu")
		(net "M_D_CPU0_SA_CA<2>")
	)
	(segment
		(start 284.877002 -260.768592)
		(end 284.749494 -260.641084)
		(width 0.18288)
		(layer "In11.Cu")
		(net "M_D_CPU0_SA_CA<2>")
	)
	(arc
		(start 336.007964 -256.850896)
		(mid 335.725262 -256.926672)
		(end 335.44256 -256.850896)
		(width 0.088646)
		(layer "In11.Cu")
		(net "M_D_CPU0_SA_CA<2>")
	)
	(arc
		(start 341.08136 -256.850896)
		(mid 340.894162 -256.800753)
		(end 340.706964 -256.850896)
		(width 0.088646)
		(layer "In11.Cu")
		(net "M_D_CPU0_SA_CA<2>")
	)
	(arc
		(start 343.901014 -256.850896)
		(mid 343.713816 -256.800753)
		(end 343.526618 -256.850896)
		(width 0.088646)
		(layer "In11.Cu")
		(net "M_D_CPU0_SA_CA<2>")
	)
	(arc
		(start 343.526618 -256.850896)
		(mid 343.252419 -256.926731)
		(end 342.975946 -256.859532)
		(width 0.088646)
		(layer "In11.Cu")
		(net "M_D_CPU0_SA_CA<2>")
	)
	(arc
		(start 334.128364 -256.850896)
		(mid 333.845662 -256.926672)
		(end 333.56296 -256.850896)
		(width 0.088646)
		(layer "In11.Cu")
		(net "M_D_CPU0_SA_CA<2>")
	)
	(arc
		(start 346.533216 -257.175254)
		(mid 346.285714 -257.008938)
		(end 345.99372 -256.948432)
		(width 0.088646)
		(layer "In11.Cu")
		(net "M_D_CPU0_SA_CA<2>")
	)
	(arc
		(start 338.827364 -256.850896)
		(mid 338.544662 -256.926672)
		(end 338.26196 -256.850896)
		(width 0.088646)
		(layer "In11.Cu")
		(net "M_D_CPU0_SA_CA<2>")
	)
	(arc
		(start 336.947764 -256.850896)
		(mid 336.665062 -256.926672)
		(end 336.38236 -256.850896)
		(width 0.088646)
		(layer "In11.Cu")
		(net "M_D_CPU0_SA_CA<2>")
	)
	(arc
		(start 344.840814 -256.850896)
		(mid 344.653616 -256.800753)
		(end 344.466418 -256.850896)
		(width 0.088646)
		(layer "In11.Cu")
		(net "M_D_CPU0_SA_CA<2>")
	)
	(arc
		(start 345.78036 -256.850896)
		(mid 345.593162 -256.800753)
		(end 345.405964 -256.850896)
		(width 0.088646)
		(layer "In11.Cu")
		(net "M_D_CPU0_SA_CA<2>")
	)
	(arc
		(start 333.56296 -256.850896)
		(mid 333.375762 -256.800753)
		(end 333.188564 -256.850896)
		(width 0.088646)
		(layer "In11.Cu")
		(net "M_D_CPU0_SA_CA<2>")
	)
	(arc
		(start 345.405964 -256.850896)
		(mid 345.129405 -256.926639)
		(end 344.851228 -256.856992)
		(width 0.088646)
		(layer "In11.Cu")
		(net "M_D_CPU0_SA_CA<2>")
	)
	(arc
		(start 333.188564 -256.850896)
		(mid 332.905862 -256.926672)
		(end 332.62316 -256.850896)
		(width 0.088646)
		(layer "In11.Cu")
		(net "M_D_CPU0_SA_CA<2>")
	)
	(arc
		(start 335.44256 -256.850896)
		(mid 335.255362 -256.800753)
		(end 335.068164 -256.850896)
		(width 0.088646)
		(layer "In11.Cu")
		(net "M_D_CPU0_SA_CA<2>")
	)
	(arc
		(start 344.466418 -256.850896)
		(mid 344.192219 -256.926731)
		(end 343.915746 -256.859532)
		(width 0.088646)
		(layer "In11.Cu")
		(net "M_D_CPU0_SA_CA<2>")
	)
	(arc
		(start 335.068164 -256.850896)
		(mid 334.785462 -256.926672)
		(end 334.50276 -256.850896)
		(width 0.088646)
		(layer "In11.Cu")
		(net "M_D_CPU0_SA_CA<2>")
	)
	(arc
		(start 339.20176 -256.850896)
		(mid 339.014562 -256.800753)
		(end 338.827364 -256.850896)
		(width 0.088646)
		(layer "In11.Cu")
		(net "M_D_CPU0_SA_CA<2>")
	)
	(arc
		(start 340.141814 -256.850896)
		(mid 339.954616 -256.800753)
		(end 339.767418 -256.850896)
		(width 0.088646)
		(layer "In11.Cu")
		(net "M_D_CPU0_SA_CA<2>")
	)
	(arc
		(start 337.32216 -256.850896)
		(mid 337.134962 -256.800753)
		(end 336.947764 -256.850896)
		(width 0.088646)
		(layer "In11.Cu")
		(net "M_D_CPU0_SA_CA<2>")
	)
	(arc
		(start 336.38236 -256.850896)
		(mid 336.195162 -256.800753)
		(end 336.007964 -256.850896)
		(width 0.088646)
		(layer "In11.Cu")
		(net "M_D_CPU0_SA_CA<2>")
	)
	(arc
		(start 337.887564 -256.850896)
		(mid 337.604862 -256.926672)
		(end 337.32216 -256.850896)
		(width 0.088646)
		(layer "In11.Cu")
		(net "M_D_CPU0_SA_CA<2>")
	)
	(arc
		(start 342.586818 -256.850896)
		(mid 342.304116 -256.926672)
		(end 342.021414 -256.850896)
		(width 0.088646)
		(layer "In11.Cu")
		(net "M_D_CPU0_SA_CA<2>")
	)
	(arc
		(start 341.647018 -256.850896)
		(mid 341.370205 -256.926766)
		(end 341.091774 -256.856992)
		(width 0.088646)
		(layer "In11.Cu")
		(net "M_D_CPU0_SA_CA<2>")
	)
	(arc
		(start 338.26196 -256.850896)
		(mid 338.074762 -256.800753)
		(end 337.887564 -256.850896)
		(width 0.088646)
		(layer "In11.Cu")
		(net "M_D_CPU0_SA_CA<2>")
	)
	(arc
		(start 339.767418 -256.850896)
		(mid 339.490605 -256.926766)
		(end 339.212174 -256.856992)
		(width 0.088646)
		(layer "In11.Cu")
		(net "M_D_CPU0_SA_CA<2>")
	)
	(arc
		(start 332.62316 -256.850896)
		(mid 332.435962 -256.800753)
		(end 332.248764 -256.850896)
		(width 0.088646)
		(layer "In11.Cu")
		(net "M_D_CPU0_SA_CA<2>")
	)
	(arc
		(start 332.248764 -256.850896)
		(mid 332.112395 -256.907338)
		(end 331.966062 -256.926588)
		(width 0.088646)
		(layer "In11.Cu")
		(net "M_D_CPU0_SA_CA<2>")
	)
	(arc
		(start 342.021414 -256.850896)
		(mid 341.834216 -256.800753)
		(end 341.647018 -256.850896)
		(width 0.088646)
		(layer "In11.Cu")
		(net "M_D_CPU0_SA_CA<2>")
	)
	(arc
		(start 334.50276 -256.850896)
		(mid 334.315562 -256.800753)
		(end 334.128364 -256.850896)
		(width 0.088646)
		(layer "In11.Cu")
		(net "M_D_CPU0_SA_CA<2>")
	)
	(arc
		(start 340.706964 -256.850896)
		(mid 340.430405 -256.926639)
		(end 340.152228 -256.856992)
		(width 0.088646)
		(layer "In11.Cu")
		(net "M_D_CPU0_SA_CA<2>")
	)
	(arc
		(start 345.99372 -256.948432)
		(mid 345.884726 -256.904725)
		(end 345.78036 -256.850896)
		(width 0.088646)
		(layer "In11.Cu")
		(net "M_D_CPU0_SA_CA<2>")
	)
	(arc
		(start 342.961214 -256.850896)
		(mid 342.774016 -256.800753)
		(end 342.586818 -256.850896)
		(width 0.088646)
		(layer "In11.Cu")
		(net "M_D_CPU0_SA_CA<2>")
	)
	(segment
		(start 265.64717 -265.312398)
		(end 265.518646 -265.440922)
		(width 0.20066)
		(layer "F.Cu")
		(net "M_D_CPU0_SA_CA<1>")
	)
	(segment
		(start 266.90828 -265.316716)
		(end 266.700762 -265.524234)
		(width 0.20066)
		(layer "F.Cu")
		(net "M_D_CPU0_SA_CA<1>")
	)
	(segment
		(start 265.518646 -265.440922)
		(end 265.518646 -265.59256)
		(width 0.20066)
		(layer "F.Cu")
		(net "M_D_CPU0_SA_CA<1>")
	)
	(segment
		(start 266.700762 -265.524234)
		(end 266.25423 -265.524234)
		(width 0.20066)
		(layer "F.Cu")
		(net "M_D_CPU0_SA_CA<1>")
	)
	(segment
		(start 262.146288 -265.755882)
		(end 262.003794 -265.613388)
		(width 0.20066)
		(layer "F.Cu")
		(net "M_D_CPU0_SA_CA<1>")
	)
	(segment
		(start 262.514334 -265.741658)
		(end 262.50011 -265.755882)
		(width 0.101854)
		(layer "F.Cu")
		(net "M_D_CPU0_SA_CA<1>")
	)
	(segment
		(start 262.003794 -265.4427)
		(end 261.87781 -265.316716)
		(width 0.20066)
		(layer "F.Cu")
		(net "M_D_CPU0_SA_CA<1>")
	)
	(segment
		(start 262.003794 -265.613388)
		(end 262.003794 -265.4427)
		(width 0.20066)
		(layer "F.Cu")
		(net "M_D_CPU0_SA_CA<1>")
	)
	(segment
		(start 264.825226 -265.741658)
		(end 262.752332 -265.741658)
		(width 0.1016)
		(layer "F.Cu")
		(net "M_D_CPU0_SA_CA<1>")
	)
	(segment
		(start 348.882716 -257.988816)
		(end 348.882462 -257.98907)
		(width 0.20066)
		(layer "F.Cu")
		(net "M_D_CPU0_SA_CA<1>")
	)
	(segment
		(start 268.829282 -265.316716)
		(end 267.724382 -265.316716)
		(width 0.20066)
		(layer "F.Cu")
		(net "M_D_CPU0_SA_CA<1>")
	)
	(segment
		(start 265.518646 -265.59256)
		(end 265.369548 -265.741658)
		(width 0.20066)
		(layer "F.Cu")
		(net "M_D_CPU0_SA_CA<1>")
	)
	(segment
		(start 266.25423 -265.524234)
		(end 266.042394 -265.312398)
		(width 0.20066)
		(layer "F.Cu")
		(net "M_D_CPU0_SA_CA<1>")
	)
	(segment
		(start 348.882716 -257.45313)
		(end 348.882716 -257.988816)
		(width 0.20066)
		(layer "F.Cu")
		(net "M_D_CPU0_SA_CA<1>")
	)
	(segment
		(start 266.042394 -265.312398)
		(end 265.64717 -265.312398)
		(width 0.20066)
		(layer "F.Cu")
		(net "M_D_CPU0_SA_CA<1>")
	)
	(segment
		(start 262.50011 -265.755882)
		(end 262.146288 -265.755882)
		(width 0.20066)
		(layer "F.Cu")
		(net "M_D_CPU0_SA_CA<1>")
	)
	(segment
		(start 261.87781 -265.316716)
		(end 260.180582 -265.316716)
		(width 0.20066)
		(layer "F.Cu")
		(net "M_D_CPU0_SA_CA<1>")
	)
	(segment
		(start 267.724382 -265.316716)
		(end 266.90828 -265.316716)
		(width 0.20066)
		(layer "F.Cu")
		(net "M_D_CPU0_SA_CA<1>")
	)
	(segment
		(start 262.752332 -265.741658)
		(end 262.514334 -265.741658)
		(width 0.101854)
		(layer "F.Cu")
		(net "M_D_CPU0_SA_CA<1>")
	)
	(segment
		(start 265.369548 -265.741658)
		(end 264.825226 -265.741658)
		(width 0.20066)
		(layer "F.Cu")
		(net "M_D_CPU0_SA_CA<1>")
	)
	(segment
		(start 300.892972 -261.314692)
		(end 300.013624 -261.314692)
		(width 0.18288)
		(layer "In11.Cu")
		(net "M_D_CPU0_SA_CA<1>")
	)
	(segment
		(start 329.317604 -257.179318)
		(end 328.82713 -257.669792)
		(width 0.18288)
		(layer "In11.Cu")
		(net "M_D_CPU0_SA_CA<1>")
	)
	(segment
		(start 284.546294 -261.490968)
		(end 282.933394 -261.490968)
		(width 0.18288)
		(layer "In11.Cu")
		(net "M_D_CPU0_SA_CA<1>")
	)
	(segment
		(start 299.837856 -261.49046)
		(end 297.705526 -261.49046)
		(width 0.18288)
		(layer "In11.Cu")
		(net "M_D_CPU0_SA_CA<1>")
	)
	(segment
		(start 331.966062 -257.42392)
		(end 331.752448 -257.42392)
		(width 0.088646)
		(layer "In11.Cu")
		(net "M_D_CPU0_SA_CA<1>")
	)
	(segment
		(start 297.546776 -261.64921)
		(end 296.327576 -261.64921)
		(width 0.18288)
		(layer "In11.Cu")
		(net "M_D_CPU0_SA_CA<1>")
	)
	(segment
		(start 276.824694 -261.675626)
		(end 275.732494 -261.675626)
		(width 0.18288)
		(layer "In11.Cu")
		(net "M_D_CPU0_SA_CA<1>")
	)
	(segment
		(start 345.790774 -257.493516)
		(end 345.78036 -257.499612)
		(width 0.088646)
		(layer "In11.Cu")
		(net "M_D_CPU0_SA_CA<1>")
	)
	(segment
		(start 305.859688 -261.04469)
		(end 305.666648 -261.23773)
		(width 0.18288)
		(layer "In11.Cu")
		(net "M_D_CPU0_SA_CA<1>")
	)
	(segment
		(start 342.036146 -257.490976)
		(end 342.021414 -257.499612)
		(width 0.088646)
		(layer "In11.Cu")
		(net "M_D_CPU0_SA_CA<1>")
	)
	(segment
		(start 296.327576 -261.64921)
		(end 296.171366 -261.493)
		(width 0.18288)
		(layer "In11.Cu")
		(net "M_D_CPU0_SA_CA<1>")
	)
	(segment
		(start 303.139094 -261.314692)
		(end 301.980092 -261.314692)
		(width 0.18288)
		(layer "In11.Cu")
		(net "M_D_CPU0_SA_CA<1>")
	)
	(segment
		(start 305.666648 -261.23773)
		(end 305.351688 -261.23773)
		(width 0.18288)
		(layer "In11.Cu")
		(net "M_D_CPU0_SA_CA<1>")
	)
	(segment
		(start 280.266394 -261.491222)
		(end 279.016968 -261.491222)
		(width 0.18288)
		(layer "In11.Cu")
		(net "M_D_CPU0_SA_CA<1>")
	)
	(segment
		(start 301.086012 -261.782052)
		(end 301.086012 -261.507732)
		(width 0.18288)
		(layer "In11.Cu")
		(net "M_D_CPU0_SA_CA<1>")
	)
	(segment
		(start 304.965608 -260.594856)
		(end 303.85893 -260.594856)
		(width 0.18288)
		(layer "In11.Cu")
		(net "M_D_CPU0_SA_CA<1>")
	)
	(segment
		(start 340.706964 -257.499612)
		(end 340.69655 -257.493516)
		(width 0.088646)
		(layer "In11.Cu")
		(net "M_D_CPU0_SA_CA<1>")
	)
	(segment
		(start 301.279052 -261.975092)
		(end 301.086012 -261.782052)
		(width 0.18288)
		(layer "In11.Cu")
		(net "M_D_CPU0_SA_CA<1>")
	)
	(segment
		(start 345.405964 -257.499612)
		(end 345.39555 -257.493516)
		(width 0.088646)
		(layer "In11.Cu")
		(net "M_D_CPU0_SA_CA<1>")
	)
	(segment
		(start 292.191694 -261.294626)
		(end 291.836094 -261.650226)
		(width 0.18288)
		(layer "In11.Cu")
		(net "M_D_CPU0_SA_CA<1>")
	)
	(segment
		(start 273.776694 -262.183626)
		(end 272.913094 -263.047226)
		(width 0.18288)
		(layer "In11.Cu")
		(net "M_D_CPU0_SA_CA<1>")
	)
	(segment
		(start 293.304468 -261.493)
		(end 293.106094 -261.294626)
		(width 0.18288)
		(layer "In11.Cu")
		(net "M_D_CPU0_SA_CA<1>")
	)
	(segment
		(start 307.119782 -260.80466)
		(end 306.909978 -260.594856)
		(width 0.18288)
		(layer "In11.Cu")
		(net "M_D_CPU0_SA_CA<1>")
	)
	(segment
		(start 306.052728 -260.594856)
		(end 305.859688 -260.787896)
		(width 0.18288)
		(layer "In11.Cu")
		(net "M_D_CPU0_SA_CA<1>")
	)
	(segment
		(start 301.086012 -261.507732)
		(end 300.892972 -261.314692)
		(width 0.18288)
		(layer "In11.Cu")
		(net "M_D_CPU0_SA_CA<1>")
	)
	(segment
		(start 319.5828 -258.363466)
		(end 315.690504 -258.363466)
		(width 0.18288)
		(layer "In11.Cu")
		(net "M_D_CPU0_SA_CA<1>")
	)
	(segment
		(start 301.594012 -261.975092)
		(end 301.279052 -261.975092)
		(width 0.18288)
		(layer "In11.Cu")
		(net "M_D_CPU0_SA_CA<1>")
	)
	(segment
		(start 270.550894 -264.69975)
		(end 269.446248 -264.69975)
		(width 0.18288)
		(layer "In11.Cu")
		(net "M_D_CPU0_SA_CA<1>")
	)
	(segment
		(start 300.013624 -261.314692)
		(end 299.837856 -261.49046)
		(width 0.18288)
		(layer "In11.Cu")
		(net "M_D_CPU0_SA_CA<1>")
	)
	(segment
		(start 278.512524 -261.671308)
		(end 278.135842 -261.294626)
		(width 0.18288)
		(layer "In11.Cu")
		(net "M_D_CPU0_SA_CA<1>")
	)
	(segment
		(start 348.30385 -257.544824)
		(end 348.225618 -257.499612)
		(width 0.088646)
		(layer "In11.Cu")
		(net "M_D_CPU0_SA_CA<1>")
	)
	(segment
		(start 338.827364 -257.499612)
		(end 338.812632 -257.490976)
		(width 0.088646)
		(layer "In11.Cu")
		(net "M_D_CPU0_SA_CA<1>")
	)
	(segment
		(start 275.732494 -261.675626)
		(end 275.224494 -262.183626)
		(width 0.18288)
		(layer "In11.Cu")
		(net "M_D_CPU0_SA_CA<1>")
	)
	(segment
		(start 269.446248 -264.69975)
		(end 268.829282 -265.316716)
		(width 0.18288)
		(layer "In11.Cu")
		(net "M_D_CPU0_SA_CA<1>")
	)
	(segment
		(start 315.690504 -258.363466)
		(end 314.542424 -259.511546)
		(width 0.18288)
		(layer "In11.Cu")
		(net "M_D_CPU0_SA_CA<1>")
	)
	(segment
		(start 293.106094 -261.294626)
		(end 292.191694 -261.294626)
		(width 0.18288)
		(layer "In11.Cu")
		(net "M_D_CPU0_SA_CA<1>")
	)
	(segment
		(start 330.927202 -257.179318)
		(end 329.317604 -257.179318)
		(width 0.18288)
		(layer "In11.Cu")
		(net "M_D_CPU0_SA_CA<1>")
	)
	(segment
		(start 347.285564 -257.499612)
		(end 347.27515 -257.493516)
		(width 0.088646)
		(layer "In11.Cu")
		(net "M_D_CPU0_SA_CA<1>")
	)
	(segment
		(start 342.975946 -257.490976)
		(end 342.961214 -257.499612)
		(width 0.088646)
		(layer "In11.Cu")
		(net "M_D_CPU0_SA_CA<1>")
	)
	(segment
		(start 310.949848 -260.062472)
		(end 310.20766 -260.80466)
		(width 0.18288)
		(layer "In11.Cu")
		(net "M_D_CPU0_SA_CA<1>")
	)
	(segment
		(start 272.913094 -263.047226)
		(end 272.203418 -263.047226)
		(width 0.18288)
		(layer "In11.Cu")
		(net "M_D_CPU0_SA_CA<1>")
	)
	(segment
		(start 341.091774 -257.493516)
		(end 341.08136 -257.499612)
		(width 0.088646)
		(layer "In11.Cu")
		(net "M_D_CPU0_SA_CA<1>")
	)
	(segment
		(start 288.145982 -261.340092)
		(end 284.69717 -261.340092)
		(width 0.18288)
		(layer "In11.Cu")
		(net "M_D_CPU0_SA_CA<1>")
	)
	(segment
		(start 320.276474 -257.669792)
		(end 319.5828 -258.363466)
		(width 0.18288)
		(layer "In11.Cu")
		(net "M_D_CPU0_SA_CA<1>")
	)
	(segment
		(start 278.836882 -261.671308)
		(end 278.512524 -261.671308)
		(width 0.18288)
		(layer "In11.Cu")
		(net "M_D_CPU0_SA_CA<1>")
	)
	(segment
		(start 301.980092 -261.314692)
		(end 301.787052 -261.507732)
		(width 0.18288)
		(layer "In11.Cu")
		(net "M_D_CPU0_SA_CA<1>")
	)
	(segment
		(start 313.088274 -259.511546)
		(end 312.537348 -260.062472)
		(width 0.18288)
		(layer "In11.Cu")
		(net "M_D_CPU0_SA_CA<1>")
	)
	(segment
		(start 288.456116 -261.650226)
		(end 288.145982 -261.340092)
		(width 0.18288)
		(layer "In11.Cu")
		(net "M_D_CPU0_SA_CA<1>")
	)
	(segment
		(start 301.787052 -261.507732)
		(end 301.787052 -261.782052)
		(width 0.18288)
		(layer "In11.Cu")
		(net "M_D_CPU0_SA_CA<1>")
	)
	(segment
		(start 278.135842 -261.294626)
		(end 277.205694 -261.294626)
		(width 0.18288)
		(layer "In11.Cu")
		(net "M_D_CPU0_SA_CA<1>")
	)
	(segment
		(start 272.203418 -263.047226)
		(end 270.550894 -264.69975)
		(width 0.18288)
		(layer "In11.Cu")
		(net "M_D_CPU0_SA_CA<1>")
	)
	(segment
		(start 314.542424 -259.511546)
		(end 313.088274 -259.511546)
		(width 0.18288)
		(layer "In11.Cu")
		(net "M_D_CPU0_SA_CA<1>")
	)
	(segment
		(start 312.537348 -260.062472)
		(end 310.949848 -260.062472)
		(width 0.18288)
		(layer "In11.Cu")
		(net "M_D_CPU0_SA_CA<1>")
	)
	(segment
		(start 305.859688 -260.787896)
		(end 305.859688 -261.04469)
		(width 0.18288)
		(layer "In11.Cu")
		(net "M_D_CPU0_SA_CA<1>")
	)
	(segment
		(start 331.507846 -257.179318)
		(end 330.927202 -257.179318)
		(width 0.088646)
		(layer "In11.Cu")
		(net "M_D_CPU0_SA_CA<1>")
	)
	(segment
		(start 305.351688 -261.23773)
		(end 305.158648 -261.04469)
		(width 0.18288)
		(layer "In11.Cu")
		(net "M_D_CPU0_SA_CA<1>")
	)
	(segment
		(start 343.915746 -257.490976)
		(end 343.901014 -257.499612)
		(width 0.088646)
		(layer "In11.Cu")
		(net "M_D_CPU0_SA_CA<1>")
	)
	(segment
		(start 306.909978 -260.594856)
		(end 306.052728 -260.594856)
		(width 0.18288)
		(layer "In11.Cu")
		(net "M_D_CPU0_SA_CA<1>")
	)
	(segment
		(start 282.933394 -261.490968)
		(end 282.266136 -262.158226)
		(width 0.18288)
		(layer "In11.Cu")
		(net "M_D_CPU0_SA_CA<1>")
	)
	(segment
		(start 310.20766 -260.80466)
		(end 307.119782 -260.80466)
		(width 0.18288)
		(layer "In11.Cu")
		(net "M_D_CPU0_SA_CA<1>")
	)
	(segment
		(start 275.224494 -262.183626)
		(end 273.776694 -262.183626)
		(width 0.18288)
		(layer "In11.Cu")
		(net "M_D_CPU0_SA_CA<1>")
	)
	(segment
		(start 331.752448 -257.42392)
		(end 331.507846 -257.179318)
		(width 0.088646)
		(layer "In11.Cu")
		(net "M_D_CPU0_SA_CA<1>")
	)
	(segment
		(start 303.85893 -260.594856)
		(end 303.139094 -261.314692)
		(width 0.18288)
		(layer "In11.Cu")
		(net "M_D_CPU0_SA_CA<1>")
	)
	(segment
		(start 280.933398 -262.158226)
		(end 280.266394 -261.491222)
		(width 0.18288)
		(layer "In11.Cu")
		(net "M_D_CPU0_SA_CA<1>")
	)
	(segment
		(start 347.670374 -257.493516)
		(end 347.65996 -257.499612)
		(width 0.088646)
		(layer "In11.Cu")
		(net "M_D_CPU0_SA_CA<1>")
	)
	(segment
		(start 297.705526 -261.49046)
		(end 297.546776 -261.64921)
		(width 0.18288)
		(layer "In11.Cu")
		(net "M_D_CPU0_SA_CA<1>")
	)
	(segment
		(start 339.212174 -257.493516)
		(end 339.20176 -257.499612)
		(width 0.088646)
		(layer "In11.Cu")
		(net "M_D_CPU0_SA_CA<1>")
	)
	(segment
		(start 296.171366 -261.493)
		(end 293.304468 -261.493)
		(width 0.18288)
		(layer "In11.Cu")
		(net "M_D_CPU0_SA_CA<1>")
	)
	(segment
		(start 305.158648 -260.787896)
		(end 304.965608 -260.594856)
		(width 0.18288)
		(layer "In11.Cu")
		(net "M_D_CPU0_SA_CA<1>")
	)
	(segment
		(start 279.016968 -261.491222)
		(end 278.836882 -261.671308)
		(width 0.18288)
		(layer "In11.Cu")
		(net "M_D_CPU0_SA_CA<1>")
	)
	(segment
		(start 301.787052 -261.782052)
		(end 301.594012 -261.975092)
		(width 0.18288)
		(layer "In11.Cu")
		(net "M_D_CPU0_SA_CA<1>")
	)
	(segment
		(start 282.266136 -262.158226)
		(end 280.933398 -262.158226)
		(width 0.18288)
		(layer "In11.Cu")
		(net "M_D_CPU0_SA_CA<1>")
	)
	(segment
		(start 305.158648 -261.04469)
		(end 305.158648 -260.787896)
		(width 0.18288)
		(layer "In11.Cu")
		(net "M_D_CPU0_SA_CA<1>")
	)
	(segment
		(start 291.836094 -261.650226)
		(end 288.456116 -261.650226)
		(width 0.18288)
		(layer "In11.Cu")
		(net "M_D_CPU0_SA_CA<1>")
	)
	(segment
		(start 284.69717 -261.340092)
		(end 284.546294 -261.490968)
		(width 0.18288)
		(layer "In11.Cu")
		(net "M_D_CPU0_SA_CA<1>")
	)
	(segment
		(start 277.205694 -261.294626)
		(end 276.824694 -261.675626)
		(width 0.18288)
		(layer "In11.Cu")
		(net "M_D_CPU0_SA_CA<1>")
	)
	(segment
		(start 328.82713 -257.669792)
		(end 320.276474 -257.669792)
		(width 0.18288)
		(layer "In11.Cu")
		(net "M_D_CPU0_SA_CA<1>")
	)
	(arc
		(start 337.887564 -257.499612)
		(mid 337.604862 -257.423836)
		(end 337.32216 -257.499612)
		(width 0.088646)
		(layer "In11.Cu")
		(net "M_D_CPU0_SA_CA<1>")
	)
	(arc
		(start 342.961214 -257.499612)
		(mid 342.774016 -257.549755)
		(end 342.586818 -257.499612)
		(width 0.088646)
		(layer "In11.Cu")
		(net "M_D_CPU0_SA_CA<1>")
	)
	(arc
		(start 339.20176 -257.499612)
		(mid 339.014562 -257.549755)
		(end 338.827364 -257.499612)
		(width 0.088646)
		(layer "In11.Cu")
		(net "M_D_CPU0_SA_CA<1>")
	)
	(arc
		(start 333.56296 -257.499612)
		(mid 333.375762 -257.549755)
		(end 333.188564 -257.499612)
		(width 0.088646)
		(layer "In11.Cu")
		(net "M_D_CPU0_SA_CA<1>")
	)
	(arc
		(start 336.947764 -257.499612)
		(mid 336.665062 -257.423836)
		(end 336.38236 -257.499612)
		(width 0.088646)
		(layer "In11.Cu")
		(net "M_D_CPU0_SA_CA<1>")
	)
	(arc
		(start 348.882462 -257.98907)
		(mid 348.607681 -257.748029)
		(end 348.30385 -257.544824)
		(width 0.088646)
		(layer "In11.Cu")
		(net "M_D_CPU0_SA_CA<1>")
	)
	(arc
		(start 332.62316 -257.499612)
		(mid 332.435962 -257.549755)
		(end 332.248764 -257.499612)
		(width 0.088646)
		(layer "In11.Cu")
		(net "M_D_CPU0_SA_CA<1>")
	)
	(arc
		(start 338.812632 -257.490976)
		(mid 338.536157 -257.423656)
		(end 338.26196 -257.499612)
		(width 0.088646)
		(layer "In11.Cu")
		(net "M_D_CPU0_SA_CA<1>")
	)
	(arc
		(start 342.586818 -257.499612)
		(mid 342.312619 -257.423777)
		(end 342.036146 -257.490976)
		(width 0.088646)
		(layer "In11.Cu")
		(net "M_D_CPU0_SA_CA<1>")
	)
	(arc
		(start 339.767418 -257.499612)
		(mid 339.490605 -257.423742)
		(end 339.212174 -257.493516)
		(width 0.088646)
		(layer "In11.Cu")
		(net "M_D_CPU0_SA_CA<1>")
	)
	(arc
		(start 337.32216 -257.499612)
		(mid 337.134962 -257.549755)
		(end 336.947764 -257.499612)
		(width 0.088646)
		(layer "In11.Cu")
		(net "M_D_CPU0_SA_CA<1>")
	)
	(arc
		(start 340.141814 -257.499612)
		(mid 339.954616 -257.549755)
		(end 339.767418 -257.499612)
		(width 0.088646)
		(layer "In11.Cu")
		(net "M_D_CPU0_SA_CA<1>")
	)
	(arc
		(start 334.50276 -257.499612)
		(mid 334.315562 -257.549755)
		(end 334.128364 -257.499612)
		(width 0.088646)
		(layer "In11.Cu")
		(net "M_D_CPU0_SA_CA<1>")
	)
	(arc
		(start 341.647018 -257.499612)
		(mid 341.370205 -257.423742)
		(end 341.091774 -257.493516)
		(width 0.088646)
		(layer "In11.Cu")
		(net "M_D_CPU0_SA_CA<1>")
	)
	(arc
		(start 341.08136 -257.499612)
		(mid 340.894162 -257.549755)
		(end 340.706964 -257.499612)
		(width 0.088646)
		(layer "In11.Cu")
		(net "M_D_CPU0_SA_CA<1>")
	)
	(arc
		(start 334.128364 -257.499612)
		(mid 333.845662 -257.423836)
		(end 333.56296 -257.499612)
		(width 0.088646)
		(layer "In11.Cu")
		(net "M_D_CPU0_SA_CA<1>")
	)
	(arc
		(start 343.901014 -257.499612)
		(mid 343.713816 -257.549755)
		(end 343.526618 -257.499612)
		(width 0.088646)
		(layer "In11.Cu")
		(net "M_D_CPU0_SA_CA<1>")
	)
	(arc
		(start 348.225618 -257.499612)
		(mid 347.948805 -257.423742)
		(end 347.670374 -257.493516)
		(width 0.088646)
		(layer "In11.Cu")
		(net "M_D_CPU0_SA_CA<1>")
	)
	(arc
		(start 347.65996 -257.499612)
		(mid 347.472762 -257.549755)
		(end 347.285564 -257.499612)
		(width 0.088646)
		(layer "In11.Cu")
		(net "M_D_CPU0_SA_CA<1>")
	)
	(arc
		(start 345.39555 -257.493516)
		(mid 345.117372 -257.423793)
		(end 344.840814 -257.499612)
		(width 0.088646)
		(layer "In11.Cu")
		(net "M_D_CPU0_SA_CA<1>")
	)
	(arc
		(start 345.78036 -257.499612)
		(mid 345.593162 -257.549755)
		(end 345.405964 -257.499612)
		(width 0.088646)
		(layer "In11.Cu")
		(net "M_D_CPU0_SA_CA<1>")
	)
	(arc
		(start 346.720414 -257.499612)
		(mid 346.533216 -257.549755)
		(end 346.346018 -257.499612)
		(width 0.088646)
		(layer "In11.Cu")
		(net "M_D_CPU0_SA_CA<1>")
	)
	(arc
		(start 333.188564 -257.499612)
		(mid 332.905862 -257.423836)
		(end 332.62316 -257.499612)
		(width 0.088646)
		(layer "In11.Cu")
		(net "M_D_CPU0_SA_CA<1>")
	)
	(arc
		(start 343.526618 -257.499612)
		(mid 343.252419 -257.423777)
		(end 342.975946 -257.490976)
		(width 0.088646)
		(layer "In11.Cu")
		(net "M_D_CPU0_SA_CA<1>")
	)
	(arc
		(start 336.38236 -257.499612)
		(mid 336.195162 -257.549755)
		(end 336.007964 -257.499612)
		(width 0.088646)
		(layer "In11.Cu")
		(net "M_D_CPU0_SA_CA<1>")
	)
	(arc
		(start 336.007964 -257.499612)
		(mid 335.725262 -257.423836)
		(end 335.44256 -257.499612)
		(width 0.088646)
		(layer "In11.Cu")
		(net "M_D_CPU0_SA_CA<1>")
	)
	(arc
		(start 335.068164 -257.499612)
		(mid 334.785462 -257.423836)
		(end 334.50276 -257.499612)
		(width 0.088646)
		(layer "In11.Cu")
		(net "M_D_CPU0_SA_CA<1>")
	)
	(arc
		(start 332.248764 -257.499612)
		(mid 332.112395 -257.44317)
		(end 331.966062 -257.42392)
		(width 0.088646)
		(layer "In11.Cu")
		(net "M_D_CPU0_SA_CA<1>")
	)
	(arc
		(start 340.69655 -257.493516)
		(mid 340.418372 -257.423793)
		(end 340.141814 -257.499612)
		(width 0.088646)
		(layer "In11.Cu")
		(net "M_D_CPU0_SA_CA<1>")
	)
	(arc
		(start 346.346018 -257.499612)
		(mid 346.069205 -257.423742)
		(end 345.790774 -257.493516)
		(width 0.088646)
		(layer "In11.Cu")
		(net "M_D_CPU0_SA_CA<1>")
	)
	(arc
		(start 338.26196 -257.499612)
		(mid 338.074762 -257.549755)
		(end 337.887564 -257.499612)
		(width 0.088646)
		(layer "In11.Cu")
		(net "M_D_CPU0_SA_CA<1>")
	)
	(arc
		(start 347.27515 -257.493516)
		(mid 346.996972 -257.423793)
		(end 346.720414 -257.499612)
		(width 0.088646)
		(layer "In11.Cu")
		(net "M_D_CPU0_SA_CA<1>")
	)
	(arc
		(start 335.44256 -257.499612)
		(mid 335.255362 -257.549755)
		(end 335.068164 -257.499612)
		(width 0.088646)
		(layer "In11.Cu")
		(net "M_D_CPU0_SA_CA<1>")
	)
	(arc
		(start 344.840814 -257.499612)
		(mid 344.653616 -257.549755)
		(end 344.466418 -257.499612)
		(width 0.088646)
		(layer "In11.Cu")
		(net "M_D_CPU0_SA_CA<1>")
	)
	(arc
		(start 342.021414 -257.499612)
		(mid 341.834216 -257.549755)
		(end 341.647018 -257.499612)
		(width 0.088646)
		(layer "In11.Cu")
		(net "M_D_CPU0_SA_CA<1>")
	)
	(arc
		(start 344.466418 -257.499612)
		(mid 344.192219 -257.423777)
		(end 343.915746 -257.490976)
		(width 0.088646)
		(layer "In11.Cu")
		(net "M_D_CPU0_SA_CA<1>")
	)
	(segment
		(start 261.984998 -266.1666)
		(end 261.560056 -265.741658)
		(width 0.20066)
		(layer "F.Cu")
		(net "M_D_CPU0_SA_CA<0>")
	)
	(segment
		(start 261.050786 -265.741658)
		(end 259.065268 -265.741658)
		(width 0.1016)
		(layer "F.Cu")
		(net "M_D_CPU0_SA_CA<0>")
	)
	(segment
		(start 258.28498 -265.895328)
		(end 258.28498 -266.223496)
		(width 0.20066)
		(layer "F.Cu")
		(net "M_D_CPU0_SA_CA<0>")
	)
	(segment
		(start 261.381494 -265.741658)
		(end 261.050786 -265.741658)
		(width 0.101854)
		(layer "F.Cu")
		(net "M_D_CPU0_SA_CA<0>")
	)
	(segment
		(start 346.063316 -257.988816)
		(end 346.063062 -257.98907)
		(width 0.20066)
		(layer "F.Cu")
		(net "M_D_CPU0_SA_CA<0>")
	)
	(segment
		(start 346.063316 -257.45313)
		(end 346.063316 -257.988816)
		(width 0.20066)
		(layer "F.Cu")
		(net "M_D_CPU0_SA_CA<0>")
	)
	(segment
		(start 259.056378 -265.732768)
		(end 258.44754 -265.732768)
		(width 0.20066)
		(layer "F.Cu")
		(net "M_D_CPU0_SA_CA<0>")
	)
	(segment
		(start 257.626104 -266.377928)
		(end 257.414776 -266.1666)
		(width 0.20066)
		(layer "F.Cu")
		(net "M_D_CPU0_SA_CA<0>")
	)
	(segment
		(start 258.130548 -266.377928)
		(end 257.626104 -266.377928)
		(width 0.20066)
		(layer "F.Cu")
		(net "M_D_CPU0_SA_CA<0>")
	)
	(segment
		(start 264.729214 -266.1666)
		(end 263.624314 -266.1666)
		(width 0.20066)
		(layer "F.Cu")
		(net "M_D_CPU0_SA_CA<0>")
	)
	(segment
		(start 261.560056 -265.741658)
		(end 261.381494 -265.741658)
		(width 0.20066)
		(layer "F.Cu")
		(net "M_D_CPU0_SA_CA<0>")
	)
	(segment
		(start 258.44754 -265.732768)
		(end 258.28498 -265.895328)
		(width 0.20066)
		(layer "F.Cu")
		(net "M_D_CPU0_SA_CA<0>")
	)
	(segment
		(start 263.624314 -266.1666)
		(end 261.984998 -266.1666)
		(width 0.20066)
		(layer "F.Cu")
		(net "M_D_CPU0_SA_CA<0>")
	)
	(segment
		(start 258.28498 -266.223496)
		(end 258.130548 -266.377928)
		(width 0.20066)
		(layer "F.Cu")
		(net "M_D_CPU0_SA_CA<0>")
	)
	(segment
		(start 257.414776 -266.1666)
		(end 256.080514 -266.1666)
		(width 0.20066)
		(layer "F.Cu")
		(net "M_D_CPU0_SA_CA<0>")
	)
	(segment
		(start 259.065268 -265.741658)
		(end 259.056378 -265.732768)
		(width 0.1016)
		(layer "F.Cu")
		(net "M_D_CPU0_SA_CA<0>")
	)
	(segment
		(start 331.653134 -257.614166)
		(end 331.563726 -257.524758)
		(width 0.088646)
		(layer "In11.Cu")
		(net "M_D_CPU0_SA_CA<0>")
	)
	(segment
		(start 330.927202 -257.524758)
		(end 329.46086 -257.524758)
		(width 0.18288)
		(layer "In11.Cu")
		(net "M_D_CPU0_SA_CA<0>")
	)
	(segment
		(start 342.116664 -257.664712)
		(end 342.101932 -257.673348)
		(width 0.088646)
		(layer "In11.Cu")
		(net "M_D_CPU0_SA_CA<0>")
	)
	(segment
		(start 293.613332 -262.412988)
		(end 292.161976 -262.412988)
		(width 0.18288)
		(layer "In11.Cu")
		(net "M_D_CPU0_SA_CA<0>")
	)
	(segment
		(start 282.046426 -263.304274)
		(end 281.336242 -263.304274)
		(width 0.18288)
		(layer "In11.Cu")
		(net "M_D_CPU0_SA_CA<0>")
	)
	(segment
		(start 277.002494 -262.209026)
		(end 276.011894 -262.209026)
		(width 0.18288)
		(layer "In11.Cu")
		(net "M_D_CPU0_SA_CA<0>")
	)
	(segment
		(start 284.61208 -262.457692)
		(end 284.495494 -262.341106)
		(width 0.18288)
		(layer "In11.Cu")
		(net "M_D_CPU0_SA_CA<0>")
	)
	(segment
		(start 278.445214 -262.341106)
		(end 278.261064 -262.525256)
		(width 0.18288)
		(layer "In11.Cu")
		(net "M_D_CPU0_SA_CA<0>")
	)
	(segment
		(start 343.056464 -257.664712)
		(end 343.041732 -257.673348)
		(width 0.088646)
		(layer "In11.Cu")
		(net "M_D_CPU0_SA_CA<0>")
	)
	(segment
		(start 281.336242 -263.304274)
		(end 280.373074 -262.341106)
		(width 0.18288)
		(layer "In11.Cu")
		(net "M_D_CPU0_SA_CA<0>")
	)
	(segment
		(start 310.355234 -261.393686)
		(end 307.198522 -261.393686)
		(width 0.18288)
		(layer "In11.Cu")
		(net "M_D_CPU0_SA_CA<0>")
	)
	(segment
		(start 296.248582 -262.18007)
		(end 296.085006 -262.343646)
		(width 0.18288)
		(layer "In11.Cu")
		(net "M_D_CPU0_SA_CA<0>")
	)
	(segment
		(start 270.25219 -265.86053)
		(end 269.935198 -265.86053)
		(width 0.18288)
		(layer "In11.Cu")
		(net "M_D_CPU0_SA_CA<0>")
	)
	(segment
		(start 299.626274 -262.341106)
		(end 297.720766 -262.341106)
		(width 0.18288)
		(layer "In11.Cu")
		(net "M_D_CPU0_SA_CA<0>")
	)
	(segment
		(start 314.754006 -260.066536)
		(end 313.336432 -260.066536)
		(width 0.18288)
		(layer "In11.Cu")
		(net "M_D_CPU0_SA_CA<0>")
	)
	(segment
		(start 269.81404 -265.739372)
		(end 265.156442 -265.739372)
		(width 0.18288)
		(layer "In11.Cu")
		(net "M_D_CPU0_SA_CA<0>")
	)
	(segment
		(start 269.935198 -265.86053)
		(end 269.81404 -265.739372)
		(width 0.18288)
		(layer "In11.Cu")
		(net "M_D_CPU0_SA_CA<0>")
	)
	(segment
		(start 344.936318 -257.664712)
		(end 344.925904 -257.670808)
		(width 0.088646)
		(layer "In11.Cu")
		(net "M_D_CPU0_SA_CA<0>")
	)
	(segment
		(start 343.996264 -257.664712)
		(end 343.981532 -257.673348)
		(width 0.088646)
		(layer "In11.Cu")
		(net "M_D_CPU0_SA_CA<0>")
	)
	(segment
		(start 328.970386 -258.015232)
		(end 320.521584 -258.015232)
		(width 0.18288)
		(layer "In11.Cu")
		(net "M_D_CPU0_SA_CA<0>")
	)
	(segment
		(start 337.802474 -257.670808)
		(end 337.79206 -257.664712)
		(width 0.088646)
		(layer "In11.Cu")
		(net "M_D_CPU0_SA_CA<0>")
	)
	(segment
		(start 278.261064 -262.525256)
		(end 277.318724 -262.525256)
		(width 0.18288)
		(layer "In11.Cu")
		(net "M_D_CPU0_SA_CA<0>")
	)
	(segment
		(start 299.795184 -262.510016)
		(end 299.626274 -262.341106)
		(width 0.18288)
		(layer "In11.Cu")
		(net "M_D_CPU0_SA_CA<0>")
	)
	(segment
		(start 284.495494 -262.341106)
		(end 283.009594 -262.341106)
		(width 0.18288)
		(layer "In11.Cu")
		(net "M_D_CPU0_SA_CA<0>")
	)
	(segment
		(start 297.720766 -262.341106)
		(end 297.55973 -262.18007)
		(width 0.18288)
		(layer "In11.Cu")
		(net "M_D_CPU0_SA_CA<0>")
	)
	(segment
		(start 311.154826 -260.594094)
		(end 310.355234 -261.393686)
		(width 0.18288)
		(layer "In11.Cu")
		(net "M_D_CPU0_SA_CA<0>")
	)
	(segment
		(start 273.624294 -263.352026)
		(end 272.887694 -264.088626)
		(width 0.18288)
		(layer "In11.Cu")
		(net "M_D_CPU0_SA_CA<0>")
	)
	(segment
		(start 345.321128 -257.670808)
		(end 345.310714 -257.664712)
		(width 0.088646)
		(layer "In11.Cu")
		(net "M_D_CPU0_SA_CA<0>")
	)
	(segment
		(start 331.966062 -257.614166)
		(end 331.653134 -257.614166)
		(width 0.088646)
		(layer "In11.Cu")
		(net "M_D_CPU0_SA_CA<0>")
	)
	(segment
		(start 302.812704 -262.510016)
		(end 299.795184 -262.510016)
		(width 0.18288)
		(layer "In11.Cu")
		(net "M_D_CPU0_SA_CA<0>")
	)
	(segment
		(start 274.868894 -263.352026)
		(end 273.624294 -263.352026)
		(width 0.18288)
		(layer "In11.Cu")
		(net "M_D_CPU0_SA_CA<0>")
	)
	(segment
		(start 296.085006 -262.343646)
		(end 293.682674 -262.343646)
		(width 0.18288)
		(layer "In11.Cu")
		(net "M_D_CPU0_SA_CA<0>")
	)
	(segment
		(start 319.585594 -258.951222)
		(end 315.86932 -258.951222)
		(width 0.18288)
		(layer "In11.Cu")
		(net "M_D_CPU0_SA_CA<0>")
	)
	(segment
		(start 312.808874 -260.594094)
		(end 311.154826 -260.594094)
		(width 0.18288)
		(layer "In11.Cu")
		(net "M_D_CPU0_SA_CA<0>")
	)
	(segment
		(start 293.682674 -262.343646)
		(end 293.613332 -262.412988)
		(width 0.18288)
		(layer "In11.Cu")
		(net "M_D_CPU0_SA_CA<0>")
	)
	(segment
		(start 340.622128 -257.670808)
		(end 340.611714 -257.664712)
		(width 0.088646)
		(layer "In11.Cu")
		(net "M_D_CPU0_SA_CA<0>")
	)
	(segment
		(start 272.887694 -264.088626)
		(end 272.024094 -264.088626)
		(width 0.18288)
		(layer "In11.Cu")
		(net "M_D_CPU0_SA_CA<0>")
	)
	(segment
		(start 331.563726 -257.524758)
		(end 330.927202 -257.524758)
		(width 0.088646)
		(layer "In11.Cu")
		(net "M_D_CPU0_SA_CA<0>")
	)
	(segment
		(start 315.86932 -258.951222)
		(end 314.754006 -260.066536)
		(width 0.18288)
		(layer "In11.Cu")
		(net "M_D_CPU0_SA_CA<0>")
	)
	(segment
		(start 272.024094 -264.088626)
		(end 270.25219 -265.86053)
		(width 0.18288)
		(layer "In11.Cu")
		(net "M_D_CPU0_SA_CA<0>")
	)
	(segment
		(start 283.009594 -262.341106)
		(end 282.046426 -263.304274)
		(width 0.18288)
		(layer "In11.Cu")
		(net "M_D_CPU0_SA_CA<0>")
	)
	(segment
		(start 265.156442 -265.739372)
		(end 264.729214 -266.1666)
		(width 0.18288)
		(layer "In11.Cu")
		(net "M_D_CPU0_SA_CA<0>")
	)
	(segment
		(start 307.198522 -261.393686)
		(end 306.822094 -261.770114)
		(width 0.18288)
		(layer "In11.Cu")
		(net "M_D_CPU0_SA_CA<0>")
	)
	(segment
		(start 297.55973 -262.18007)
		(end 296.248582 -262.18007)
		(width 0.18288)
		(layer "In11.Cu")
		(net "M_D_CPU0_SA_CA<0>")
	)
	(segment
		(start 280.373074 -262.341106)
		(end 278.445214 -262.341106)
		(width 0.18288)
		(layer "In11.Cu")
		(net "M_D_CPU0_SA_CA<0>")
	)
	(segment
		(start 276.011894 -262.209026)
		(end 274.868894 -263.352026)
		(width 0.18288)
		(layer "In11.Cu")
		(net "M_D_CPU0_SA_CA<0>")
	)
	(segment
		(start 338.742528 -257.670808)
		(end 338.732114 -257.664712)
		(width 0.088646)
		(layer "In11.Cu")
		(net "M_D_CPU0_SA_CA<0>")
	)
	(segment
		(start 292.161976 -262.412988)
		(end 291.958014 -262.209026)
		(width 0.18288)
		(layer "In11.Cu")
		(net "M_D_CPU0_SA_CA<0>")
	)
	(segment
		(start 340.237318 -257.664712)
		(end 340.226904 -257.670808)
		(width 0.088646)
		(layer "In11.Cu")
		(net "M_D_CPU0_SA_CA<0>")
	)
	(segment
		(start 313.336432 -260.066536)
		(end 312.808874 -260.594094)
		(width 0.18288)
		(layer "In11.Cu")
		(net "M_D_CPU0_SA_CA<0>")
	)
	(segment
		(start 288.597848 -262.209026)
		(end 288.349182 -262.457692)
		(width 0.18288)
		(layer "In11.Cu")
		(net "M_D_CPU0_SA_CA<0>")
	)
	(segment
		(start 345.534742 -257.737356)
		(end 345.534488 -257.737356)
		(width 0.088646)
		(layer "In11.Cu")
		(net "M_D_CPU0_SA_CA<0>")
	)
	(segment
		(start 306.822094 -261.770114)
		(end 303.552606 -261.770114)
		(width 0.18288)
		(layer "In11.Cu")
		(net "M_D_CPU0_SA_CA<0>")
	)
	(segment
		(start 291.958014 -262.209026)
		(end 288.597848 -262.209026)
		(width 0.18288)
		(layer "In11.Cu")
		(net "M_D_CPU0_SA_CA<0>")
	)
	(segment
		(start 277.318724 -262.525256)
		(end 277.002494 -262.209026)
		(width 0.18288)
		(layer "In11.Cu")
		(net "M_D_CPU0_SA_CA<0>")
	)
	(segment
		(start 329.46086 -257.524758)
		(end 328.970386 -258.015232)
		(width 0.18288)
		(layer "In11.Cu")
		(net "M_D_CPU0_SA_CA<0>")
	)
	(segment
		(start 320.521584 -258.015232)
		(end 319.585594 -258.951222)
		(width 0.18288)
		(layer "In11.Cu")
		(net "M_D_CPU0_SA_CA<0>")
	)
	(segment
		(start 303.552606 -261.770114)
		(end 302.812704 -262.510016)
		(width 0.18288)
		(layer "In11.Cu")
		(net "M_D_CPU0_SA_CA<0>")
	)
	(segment
		(start 288.349182 -262.457692)
		(end 284.61208 -262.457692)
		(width 0.18288)
		(layer "In11.Cu")
		(net "M_D_CPU0_SA_CA<0>")
	)
	(arc
		(start 337.417664 -257.664712)
		(mid 337.134962 -257.740488)
		(end 336.85226 -257.664712)
		(width 0.088646)
		(layer "In11.Cu")
		(net "M_D_CPU0_SA_CA<0>")
	)
	(arc
		(start 341.176864 -257.664712)
		(mid 340.900305 -257.740455)
		(end 340.622128 -257.670808)
		(width 0.088646)
		(layer "In11.Cu")
		(net "M_D_CPU0_SA_CA<0>")
	)
	(arc
		(start 343.981532 -257.673348)
		(mid 343.705057 -257.740668)
		(end 343.43086 -257.664712)
		(width 0.088646)
		(layer "In11.Cu")
		(net "M_D_CPU0_SA_CA<0>")
	)
	(arc
		(start 336.477864 -257.664712)
		(mid 336.195162 -257.740488)
		(end 335.91246 -257.664712)
		(width 0.088646)
		(layer "In11.Cu")
		(net "M_D_CPU0_SA_CA<0>")
	)
	(arc
		(start 332.718664 -257.664712)
		(mid 332.435962 -257.740488)
		(end 332.15326 -257.664712)
		(width 0.088646)
		(layer "In11.Cu")
		(net "M_D_CPU0_SA_CA<0>")
	)
	(arc
		(start 345.310714 -257.664712)
		(mid 345.123516 -257.614569)
		(end 344.936318 -257.664712)
		(width 0.088646)
		(layer "In11.Cu")
		(net "M_D_CPU0_SA_CA<0>")
	)
	(arc
		(start 342.49106 -257.664712)
		(mid 342.303862 -257.614569)
		(end 342.116664 -257.664712)
		(width 0.088646)
		(layer "In11.Cu")
		(net "M_D_CPU0_SA_CA<0>")
	)
	(arc
		(start 343.43086 -257.664712)
		(mid 343.243662 -257.614569)
		(end 343.056464 -257.664712)
		(width 0.088646)
		(layer "In11.Cu")
		(net "M_D_CPU0_SA_CA<0>")
	)
	(arc
		(start 338.732114 -257.664712)
		(mid 338.544916 -257.614569)
		(end 338.357718 -257.664712)
		(width 0.088646)
		(layer "In11.Cu")
		(net "M_D_CPU0_SA_CA<0>")
	)
	(arc
		(start 345.534488 -257.737356)
		(mid 345.424497 -257.714707)
		(end 345.321128 -257.670808)
		(width 0.088646)
		(layer "In11.Cu")
		(net "M_D_CPU0_SA_CA<0>")
	)
	(arc
		(start 334.97266 -257.664712)
		(mid 334.785462 -257.614569)
		(end 334.598264 -257.664712)
		(width 0.088646)
		(layer "In11.Cu")
		(net "M_D_CPU0_SA_CA<0>")
	)
	(arc
		(start 333.09306 -257.664712)
		(mid 332.905862 -257.614569)
		(end 332.718664 -257.664712)
		(width 0.088646)
		(layer "In11.Cu")
		(net "M_D_CPU0_SA_CA<0>")
	)
	(arc
		(start 342.101932 -257.673348)
		(mid 341.825457 -257.740668)
		(end 341.55126 -257.664712)
		(width 0.088646)
		(layer "In11.Cu")
		(net "M_D_CPU0_SA_CA<0>")
	)
	(arc
		(start 335.538064 -257.664712)
		(mid 335.255362 -257.740488)
		(end 334.97266 -257.664712)
		(width 0.088646)
		(layer "In11.Cu")
		(net "M_D_CPU0_SA_CA<0>")
	)
	(arc
		(start 334.03286 -257.664712)
		(mid 333.845662 -257.614569)
		(end 333.658464 -257.664712)
		(width 0.088646)
		(layer "In11.Cu")
		(net "M_D_CPU0_SA_CA<0>")
	)
	(arc
		(start 339.67166 -257.664712)
		(mid 339.484462 -257.614569)
		(end 339.297264 -257.664712)
		(width 0.088646)
		(layer "In11.Cu")
		(net "M_D_CPU0_SA_CA<0>")
	)
	(arc
		(start 344.925904 -257.670808)
		(mid 344.647472 -257.740654)
		(end 344.37066 -257.664712)
		(width 0.088646)
		(layer "In11.Cu")
		(net "M_D_CPU0_SA_CA<0>")
	)
	(arc
		(start 334.598264 -257.664712)
		(mid 334.315562 -257.740488)
		(end 334.03286 -257.664712)
		(width 0.088646)
		(layer "In11.Cu")
		(net "M_D_CPU0_SA_CA<0>")
	)
	(arc
		(start 337.79206 -257.664712)
		(mid 337.604862 -257.614569)
		(end 337.417664 -257.664712)
		(width 0.088646)
		(layer "In11.Cu")
		(net "M_D_CPU0_SA_CA<0>")
	)
	(arc
		(start 344.37066 -257.664712)
		(mid 344.183462 -257.614569)
		(end 343.996264 -257.664712)
		(width 0.088646)
		(layer "In11.Cu")
		(net "M_D_CPU0_SA_CA<0>")
	)
	(arc
		(start 338.357718 -257.664712)
		(mid 338.080905 -257.740582)
		(end 337.802474 -257.670808)
		(width 0.088646)
		(layer "In11.Cu")
		(net "M_D_CPU0_SA_CA<0>")
	)
	(arc
		(start 340.611714 -257.664712)
		(mid 340.424516 -257.614569)
		(end 340.237318 -257.664712)
		(width 0.088646)
		(layer "In11.Cu")
		(net "M_D_CPU0_SA_CA<0>")
	)
	(arc
		(start 335.91246 -257.664712)
		(mid 335.725262 -257.614569)
		(end 335.538064 -257.664712)
		(width 0.088646)
		(layer "In11.Cu")
		(net "M_D_CPU0_SA_CA<0>")
	)
	(arc
		(start 332.15326 -257.664712)
		(mid 332.062988 -257.627113)
		(end 331.966062 -257.614166)
		(width 0.088646)
		(layer "In11.Cu")
		(net "M_D_CPU0_SA_CA<0>")
	)
	(arc
		(start 333.658464 -257.664712)
		(mid 333.375762 -257.740488)
		(end 333.09306 -257.664712)
		(width 0.088646)
		(layer "In11.Cu")
		(net "M_D_CPU0_SA_CA<0>")
	)
	(arc
		(start 340.226904 -257.670808)
		(mid 339.948472 -257.740654)
		(end 339.67166 -257.664712)
		(width 0.088646)
		(layer "In11.Cu")
		(net "M_D_CPU0_SA_CA<0>")
	)
	(arc
		(start 343.041732 -257.673348)
		(mid 342.765257 -257.740668)
		(end 342.49106 -257.664712)
		(width 0.088646)
		(layer "In11.Cu")
		(net "M_D_CPU0_SA_CA<0>")
	)
	(arc
		(start 346.063062 -257.98907)
		(mid 345.820571 -257.817722)
		(end 345.534742 -257.737356)
		(width 0.088646)
		(layer "In11.Cu")
		(net "M_D_CPU0_SA_CA<0>")
	)
	(arc
		(start 339.297264 -257.664712)
		(mid 339.020705 -257.740455)
		(end 338.742528 -257.670808)
		(width 0.088646)
		(layer "In11.Cu")
		(net "M_D_CPU0_SA_CA<0>")
	)
	(arc
		(start 336.85226 -257.664712)
		(mid 336.665062 -257.614569)
		(end 336.477864 -257.664712)
		(width 0.088646)
		(layer "In11.Cu")
		(net "M_D_CPU0_SA_CA<0>")
	)
	(arc
		(start 341.55126 -257.664712)
		(mid 341.364062 -257.614569)
		(end 341.176864 -257.664712)
		(width 0.088646)
		(layer "In11.Cu")
		(net "M_D_CPU0_SA_CA<0>")
	)
	(segment
		(start 268.829282 -260.21665)
		(end 267.724382 -260.21665)
		(width 0.20066)
		(layer "F.Cu")
		(net "M_D_CPU0_CLK_DP<1>")
	)
	(segment
		(start 348.772734 -250.155964)
		(end 348.77248 -250.15571)
		(width 0.20066)
		(layer "F.Cu")
		(net "M_D_CPU0_CLK_DP<1>")
	)
	(segment
		(start 348.77248 -250.15571)
		(end 348.77248 -249.620024)
		(width 0.20066)
		(layer "F.Cu")
		(net "M_D_CPU0_CLK_DP<1>")
	)
	(segment
		(start 286.799782 -256.48412)
		(end 286.287972 -255.97231)
		(width 0.18288)
		(layer "In11.Cu")
		(net "M_D_CPU0_CLK_DP<1>")
	)
	(segment
		(start 311.574688 -255.755394)
		(end 305.858926 -255.755394)
		(width 0.18288)
		(layer "In11.Cu")
		(net "M_D_CPU0_CLK_DP<1>")
	)
	(segment
		(start 305.112928 -256.501392)
		(end 301.737014 -256.501392)
		(width 0.18288)
		(layer "In11.Cu")
		(net "M_D_CPU0_CLK_DP<1>")
	)
	(segment
		(start 301.737014 -256.501392)
		(end 301.29353 -256.057908)
		(width 0.18288)
		(layer "In11.Cu")
		(net "M_D_CPU0_CLK_DP<1>")
	)
	(segment
		(start 346.710254 -252.413008)
		(end 334.450944 -252.413008)
		(width 0.18288)
		(layer "In11.Cu")
		(net "M_D_CPU0_CLK_DP<1>")
	)
	(segment
		(start 282.802838 -255.97231)
		(end 282.347416 -256.427732)
		(width 0.18288)
		(layer "In11.Cu")
		(net "M_D_CPU0_CLK_DP<1>")
	)
	(segment
		(start 305.858926 -255.755394)
		(end 305.112928 -256.501392)
		(width 0.18288)
		(layer "In11.Cu")
		(net "M_D_CPU0_CLK_DP<1>")
	)
	(segment
		(start 274.65909 -256.544826)
		(end 271.419066 -256.544826)
		(width 0.18288)
		(layer "In11.Cu")
		(net "M_D_CPU0_CLK_DP<1>")
	)
	(segment
		(start 297.725338 -256.057908)
		(end 297.385994 -256.397252)
		(width 0.18288)
		(layer "In11.Cu")
		(net "M_D_CPU0_CLK_DP<1>")
	)
	(segment
		(start 348.477078 -250.646184)
		(end 346.710254 -252.413008)
		(width 0.18288)
		(layer "In11.Cu")
		(net "M_D_CPU0_CLK_DP<1>")
	)
	(segment
		(start 323.855588 -255.218438)
		(end 322.818252 -254.181102)
		(width 0.18288)
		(layer "In11.Cu")
		(net "M_D_CPU0_CLK_DP<1>")
	)
	(segment
		(start 269.613634 -259.306314)
		(end 269.08506 -259.834888)
		(width 0.18288)
		(layer "In11.Cu")
		(net "M_D_CPU0_CLK_DP<1>")
	)
	(segment
		(start 301.29353 -256.057908)
		(end 297.725338 -256.057908)
		(width 0.18288)
		(layer "In11.Cu")
		(net "M_D_CPU0_CLK_DP<1>")
	)
	(segment
		(start 297.385994 -256.397252)
		(end 294.320976 -256.397252)
		(width 0.18288)
		(layer "In11.Cu")
		(net "M_D_CPU0_CLK_DP<1>")
	)
	(segment
		(start 269.08506 -259.834888)
		(end 269.08506 -259.960872)
		(width 0.18288)
		(layer "In11.Cu")
		(net "M_D_CPU0_CLK_DP<1>")
	)
	(segment
		(start 269.613634 -258.350258)
		(end 269.613634 -259.306314)
		(width 0.18288)
		(layer "In11.Cu")
		(net "M_D_CPU0_CLK_DP<1>")
	)
	(segment
		(start 271.419066 -256.544826)
		(end 269.613634 -258.350258)
		(width 0.18288)
		(layer "In11.Cu")
		(net "M_D_CPU0_CLK_DP<1>")
	)
	(segment
		(start 329.75804 -253.18466)
		(end 327.724262 -255.218438)
		(width 0.18288)
		(layer "In11.Cu")
		(net "M_D_CPU0_CLK_DP<1>")
	)
	(segment
		(start 334.195166 -252.668786)
		(end 331.003402 -252.668786)
		(width 0.18288)
		(layer "In11.Cu")
		(net "M_D_CPU0_CLK_DP<1>")
	)
	(segment
		(start 293.92499 -256.001266)
		(end 290.260786 -256.001266)
		(width 0.18288)
		(layer "In11.Cu")
		(net "M_D_CPU0_CLK_DP<1>")
	)
	(segment
		(start 348.477078 -249.915426)
		(end 348.477078 -250.646184)
		(width 0.18288)
		(layer "In11.Cu")
		(net "M_D_CPU0_CLK_DP<1>")
	)
	(segment
		(start 315.371734 -254.181102)
		(end 311.574688 -255.755394)
		(width 0.18288)
		(layer "In11.Cu")
		(net "M_D_CPU0_CLK_DP<1>")
	)
	(segment
		(start 327.724262 -255.218438)
		(end 323.855588 -255.218438)
		(width 0.18288)
		(layer "In11.Cu")
		(net "M_D_CPU0_CLK_DP<1>")
	)
	(segment
		(start 282.347416 -256.427732)
		(end 279.197054 -256.427732)
		(width 0.18288)
		(layer "In11.Cu")
		(net "M_D_CPU0_CLK_DP<1>")
	)
	(segment
		(start 294.320976 -256.397252)
		(end 293.92499 -256.001266)
		(width 0.18288)
		(layer "In11.Cu")
		(net "M_D_CPU0_CLK_DP<1>")
	)
	(segment
		(start 290.260786 -256.001266)
		(end 289.777932 -256.48412)
		(width 0.18288)
		(layer "In11.Cu")
		(net "M_D_CPU0_CLK_DP<1>")
	)
	(segment
		(start 278.817324 -256.048002)
		(end 275.155914 -256.048002)
		(width 0.18288)
		(layer "In11.Cu")
		(net "M_D_CPU0_CLK_DP<1>")
	)
	(segment
		(start 330.18476 -253.007876)
		(end 329.75804 -253.18466)
		(width 0.18288)
		(layer "In11.Cu")
		(net "M_D_CPU0_CLK_DP<1>")
	)
	(segment
		(start 331.003402 -252.668786)
		(end 330.18476 -253.007876)
		(width 0.18288)
		(layer "In11.Cu")
		(net "M_D_CPU0_CLK_DP<1>")
	)
	(segment
		(start 289.777932 -256.48412)
		(end 286.799782 -256.48412)
		(width 0.18288)
		(layer "In11.Cu")
		(net "M_D_CPU0_CLK_DP<1>")
	)
	(segment
		(start 348.77248 -249.620024)
		(end 348.477078 -249.915426)
		(width 0.18288)
		(layer "In11.Cu")
		(net "M_D_CPU0_CLK_DP<1>")
	)
	(segment
		(start 275.155914 -256.048002)
		(end 274.65909 -256.544826)
		(width 0.18288)
		(layer "In11.Cu")
		(net "M_D_CPU0_CLK_DP<1>")
	)
	(segment
		(start 279.197054 -256.427732)
		(end 278.817324 -256.048002)
		(width 0.18288)
		(layer "In11.Cu")
		(net "M_D_CPU0_CLK_DP<1>")
	)
	(segment
		(start 322.818252 -254.181102)
		(end 315.371734 -254.181102)
		(width 0.18288)
		(layer "In11.Cu")
		(net "M_D_CPU0_CLK_DP<1>")
	)
	(segment
		(start 334.450944 -252.413008)
		(end 334.195166 -252.668786)
		(width 0.18288)
		(layer "In11.Cu")
		(net "M_D_CPU0_CLK_DP<1>")
	)
	(segment
		(start 286.287972 -255.97231)
		(end 282.802838 -255.97231)
		(width 0.18288)
		(layer "In11.Cu")
		(net "M_D_CPU0_CLK_DP<1>")
	)
	(segment
		(start 269.08506 -259.960872)
		(end 268.829282 -260.21665)
		(width 0.18288)
		(layer "In11.Cu")
		(net "M_D_CPU0_CLK_DP<1>")
	)
	(segment
		(start 261.285482 -260.21665)
		(end 260.180582 -260.21665)
		(width 0.20066)
		(layer "F.Cu")
		(net "M_D_CPU0_CLK_DP<0>")
	)
	(segment
		(start 346.893134 -249.620278)
		(end 346.89288 -249.620024)
		(width 0.20066)
		(layer "F.Cu")
		(net "M_D_CPU0_CLK_DP<0>")
	)
	(segment
		(start 346.893134 -250.155964)
		(end 346.893134 -249.620278)
		(width 0.20066)
		(layer "F.Cu")
		(net "M_D_CPU0_CLK_DP<0>")
	)
	(segment
		(start 301.65167 -255.229868)
		(end 297.377358 -255.229868)
		(width 0.18288)
		(layer "In11.Cu")
		(net "M_D_CPU0_CLK_DP<0>")
	)
	(segment
		(start 311.868312 -252.104652)
		(end 311.177686 -252.104652)
		(width 0.18288)
		(layer "In11.Cu")
		(net "M_D_CPU0_CLK_DP<0>")
	)
	(segment
		(start 330.073254 -251.779786)
		(end 327.307448 -254.545592)
		(width 0.18288)
		(layer "In11.Cu")
		(net "M_D_CPU0_CLK_DP<0>")
	)
	(segment
		(start 270.369792 -255.706626)
		(end 268.169898 -257.90652)
		(width 0.18288)
		(layer "In11.Cu")
		(net "M_D_CPU0_CLK_DP<0>")
	)
	(segment
		(start 305.86172 -253.936246)
		(end 305.437794 -254.360172)
		(width 0.18288)
		(layer "In11.Cu")
		(net "M_D_CPU0_CLK_DP<0>")
	)
	(segment
		(start 278.94026 -254.991108)
		(end 275.022564 -254.991108)
		(width 0.18288)
		(layer "In11.Cu")
		(net "M_D_CPU0_CLK_DP<0>")
	)
	(segment
		(start 268.169898 -257.90652)
		(end 264.772648 -257.90652)
		(width 0.18288)
		(layer "In11.Cu")
		(net "M_D_CPU0_CLK_DP<0>")
	)
	(segment
		(start 275.022564 -254.991108)
		(end 274.307046 -255.706626)
		(width 0.18288)
		(layer "In11.Cu")
		(net "M_D_CPU0_CLK_DP<0>")
	)
	(segment
		(start 287.127442 -255.630426)
		(end 286.471106 -254.97409)
		(width 0.18288)
		(layer "In11.Cu")
		(net "M_D_CPU0_CLK_DP<0>")
	)
	(segment
		(start 294.682164 -255.568958)
		(end 294.283384 -255.170178)
		(width 0.18288)
		(layer "In11.Cu")
		(net "M_D_CPU0_CLK_DP<0>")
	)
	(segment
		(start 322.810886 -252.94209)
		(end 315.95441 -252.94209)
		(width 0.18288)
		(layer "In11.Cu")
		(net "M_D_CPU0_CLK_DP<0>")
	)
	(segment
		(start 261.831328 -259.958078)
		(end 261.544054 -259.958078)
		(width 0.18288)
		(layer "In11.Cu")
		(net "M_D_CPU0_CLK_DP<0>")
	)
	(segment
		(start 282.603702 -254.97409)
		(end 281.97937 -255.598422)
		(width 0.18288)
		(layer "In11.Cu")
		(net "M_D_CPU0_CLK_DP<0>")
	)
	(segment
		(start 297.038268 -255.568958)
		(end 294.682164 -255.568958)
		(width 0.18288)
		(layer "In11.Cu")
		(net "M_D_CPU0_CLK_DP<0>")
	)
	(segment
		(start 324.414388 -254.545592)
		(end 322.810886 -252.94209)
		(width 0.18288)
		(layer "In11.Cu")
		(net "M_D_CPU0_CLK_DP<0>")
	)
	(segment
		(start 279.547574 -255.598422)
		(end 278.94026 -254.991108)
		(width 0.18288)
		(layer "In11.Cu")
		(net "M_D_CPU0_CLK_DP<0>")
	)
	(segment
		(start 305.437794 -254.360172)
		(end 305.437794 -254.893318)
		(width 0.18288)
		(layer "In11.Cu")
		(net "M_D_CPU0_CLK_DP<0>")
	)
	(segment
		(start 346.89288 -249.620024)
		(end 346.585286 -249.927618)
		(width 0.18288)
		(layer "In11.Cu")
		(net "M_D_CPU0_CLK_DP<0>")
	)
	(segment
		(start 281.97937 -255.598422)
		(end 279.547574 -255.598422)
		(width 0.18288)
		(layer "In11.Cu")
		(net "M_D_CPU0_CLK_DP<0>")
	)
	(segment
		(start 274.307046 -255.706626)
		(end 270.369792 -255.706626)
		(width 0.18288)
		(layer "In11.Cu")
		(net "M_D_CPU0_CLK_DP<0>")
	)
	(segment
		(start 346.585286 -250.702826)
		(end 345.743276 -251.544836)
		(width 0.18288)
		(layer "In11.Cu")
		(net "M_D_CPU0_CLK_DP<0>")
	)
	(segment
		(start 304.700686 -255.630426)
		(end 302.052228 -255.630426)
		(width 0.18288)
		(layer "In11.Cu")
		(net "M_D_CPU0_CLK_DP<0>")
	)
	(segment
		(start 286.471106 -254.97409)
		(end 282.603702 -254.97409)
		(width 0.18288)
		(layer "In11.Cu")
		(net "M_D_CPU0_CLK_DP<0>")
	)
	(segment
		(start 311.177686 -252.104652)
		(end 307.192934 -253.936246)
		(width 0.18288)
		(layer "In11.Cu")
		(net "M_D_CPU0_CLK_DP<0>")
	)
	(segment
		(start 315.95441 -252.94209)
		(end 311.868312 -252.104652)
		(width 0.18288)
		(layer "In11.Cu")
		(net "M_D_CPU0_CLK_DP<0>")
	)
	(segment
		(start 327.307448 -254.545592)
		(end 324.414388 -254.545592)
		(width 0.18288)
		(layer "In11.Cu")
		(net "M_D_CPU0_CLK_DP<0>")
	)
	(segment
		(start 262.900922 -259.514086)
		(end 261.831328 -259.958078)
		(width 0.18288)
		(layer "In11.Cu")
		(net "M_D_CPU0_CLK_DP<0>")
	)
	(segment
		(start 264.32129 -258.093718)
		(end 262.900922 -259.514086)
		(width 0.18288)
		(layer "In11.Cu")
		(net "M_D_CPU0_CLK_DP<0>")
	)
	(segment
		(start 264.772648 -257.90652)
		(end 264.32129 -258.093718)
		(width 0.18288)
		(layer "In11.Cu")
		(net "M_D_CPU0_CLK_DP<0>")
	)
	(segment
		(start 346.585286 -249.927618)
		(end 346.585286 -250.702826)
		(width 0.18288)
		(layer "In11.Cu")
		(net "M_D_CPU0_CLK_DP<0>")
	)
	(segment
		(start 289.426142 -255.630426)
		(end 287.127442 -255.630426)
		(width 0.18288)
		(layer "In11.Cu")
		(net "M_D_CPU0_CLK_DP<0>")
	)
	(segment
		(start 302.052228 -255.630426)
		(end 301.65167 -255.229868)
		(width 0.18288)
		(layer "In11.Cu")
		(net "M_D_CPU0_CLK_DP<0>")
	)
	(segment
		(start 305.437794 -254.893318)
		(end 304.700686 -255.630426)
		(width 0.18288)
		(layer "In11.Cu")
		(net "M_D_CPU0_CLK_DP<0>")
	)
	(segment
		(start 289.88639 -255.170178)
		(end 289.426142 -255.630426)
		(width 0.18288)
		(layer "In11.Cu")
		(net "M_D_CPU0_CLK_DP<0>")
	)
	(segment
		(start 333.739744 -251.779786)
		(end 330.073254 -251.779786)
		(width 0.18288)
		(layer "In11.Cu")
		(net "M_D_CPU0_CLK_DP<0>")
	)
	(segment
		(start 345.743276 -251.544836)
		(end 333.974694 -251.544836)
		(width 0.18288)
		(layer "In11.Cu")
		(net "M_D_CPU0_CLK_DP<0>")
	)
	(segment
		(start 297.377358 -255.229868)
		(end 297.038268 -255.568958)
		(width 0.18288)
		(layer "In11.Cu")
		(net "M_D_CPU0_CLK_DP<0>")
	)
	(segment
		(start 333.974694 -251.544836)
		(end 333.739744 -251.779786)
		(width 0.18288)
		(layer "In11.Cu")
		(net "M_D_CPU0_CLK_DP<0>")
	)
	(segment
		(start 294.283384 -255.170178)
		(end 289.88639 -255.170178)
		(width 0.18288)
		(layer "In11.Cu")
		(net "M_D_CPU0_CLK_DP<0>")
	)
	(segment
		(start 261.544054 -259.958078)
		(end 261.285482 -260.21665)
		(width 0.18288)
		(layer "In11.Cu")
		(net "M_D_CPU0_CLK_DP<0>")
	)
	(segment
		(start 307.192934 -253.936246)
		(end 305.86172 -253.936246)
		(width 0.18288)
		(layer "In11.Cu")
		(net "M_D_CPU0_CLK_DP<0>")
	)
	(segment
		(start 347.832934 -250.155964)
		(end 347.83268 -250.15571)
		(width 0.20066)
		(layer "F.Cu")
		(net "M_D_CPU0_CLK_DN<1>")
	)
	(segment
		(start 347.83268 -250.15571)
		(end 347.83268 -249.620024)
		(width 0.20066)
		(layer "F.Cu")
		(net "M_D_CPU0_CLK_DN<1>")
	)
	(segment
		(start 268.829282 -259.366766)
		(end 267.724382 -259.366766)
		(width 0.20066)
		(layer "F.Cu")
		(net "M_D_CPU0_CLK_DN<1>")
	)
	(segment
		(start 290.132262 -255.691386)
		(end 289.649408 -256.17424)
		(width 0.18288)
		(layer "In11.Cu")
		(net "M_D_CPU0_CLK_DN<1>")
	)
	(segment
		(start 322.946776 -253.871222)
		(end 322.413376 -253.871222)
		(width 0.18288)
		(layer "In11.Cu")
		(net "M_D_CPU0_CLK_DN<1>")
	)
	(segment
		(start 319.792096 -253.871222)
		(end 319.670176 -253.749302)
		(width 0.18288)
		(layer "In11.Cu")
		(net "M_D_CPU0_CLK_DN<1>")
	)
	(segment
		(start 334.32242 -252.103128)
		(end 334.066642 -252.358906)
		(width 0.18288)
		(layer "In11.Cu")
		(net "M_D_CPU0_CLK_DN<1>")
	)
	(segment
		(start 301.865538 -256.191512)
		(end 301.422054 -255.748028)
		(width 0.18288)
		(layer "In11.Cu")
		(net "M_D_CPU0_CLK_DN<1>")
	)
	(segment
		(start 313.103514 -254.785876)
		(end 312.944256 -254.72009)
		(width 0.18288)
		(layer "In11.Cu")
		(net "M_D_CPU0_CLK_DN<1>")
	)
	(segment
		(start 268.830044 -259.366004)
		(end 268.829282 -259.366766)
		(width 0.18288)
		(layer "In11.Cu")
		(net "M_D_CPU0_CLK_DN<1>")
	)
	(segment
		(start 312.385202 -255.083818)
		(end 311.512966 -255.445514)
		(width 0.18288)
		(layer "In11.Cu")
		(net "M_D_CPU0_CLK_DN<1>")
	)
	(segment
		(start 269.303754 -259.17779)
		(end 269.11554 -259.366004)
		(width 0.18288)
		(layer "In11.Cu")
		(net "M_D_CPU0_CLK_DN<1>")
	)
	(segment
		(start 308.048152 -255.445514)
		(end 305.730402 -255.445514)
		(width 0.18288)
		(layer "In11.Cu")
		(net "M_D_CPU0_CLK_DN<1>")
	)
	(segment
		(start 330.94168 -252.358906)
		(end 330.066396 -252.721364)
		(width 0.18288)
		(layer "In11.Cu")
		(net "M_D_CPU0_CLK_DN<1>")
	)
	(segment
		(start 319.014856 -253.871222)
		(end 318.481456 -253.871222)
		(width 0.18288)
		(layer "In11.Cu")
		(net "M_D_CPU0_CLK_DN<1>")
	)
	(segment
		(start 330.066396 -252.721364)
		(end 329.582272 -252.92177)
		(width 0.18288)
		(layer "In11.Cu")
		(net "M_D_CPU0_CLK_DN<1>")
	)
	(segment
		(start 313.99226 -254.285242)
		(end 313.92622 -254.444754)
		(width 0.18288)
		(layer "In11.Cu")
		(net "M_D_CPU0_CLK_DN<1>")
	)
	(segment
		(start 309.358792 -255.445514)
		(end 308.825392 -255.445514)
		(width 0.18288)
		(layer "In11.Cu")
		(net "M_D_CPU0_CLK_DN<1>")
	)
	(segment
		(start 323.984112 -254.908558)
		(end 322.946776 -253.871222)
		(width 0.18288)
		(layer "In11.Cu")
		(net "M_D_CPU0_CLK_DN<1>")
	)
	(segment
		(start 317.704216 -253.871222)
		(end 317.170816 -253.871222)
		(width 0.18288)
		(layer "In11.Cu")
		(net "M_D_CPU0_CLK_DN<1>")
	)
	(segment
		(start 313.92622 -254.444754)
		(end 313.103514 -254.785876)
		(width 0.18288)
		(layer "In11.Cu")
		(net "M_D_CPU0_CLK_DN<1>")
	)
	(segment
		(start 297.25747 -256.087372)
		(end 294.4495 -256.087372)
		(width 0.18288)
		(layer "In11.Cu")
		(net "M_D_CPU0_CLK_DN<1>")
	)
	(segment
		(start 319.670176 -253.749302)
		(end 319.136776 -253.749302)
		(width 0.18288)
		(layer "In11.Cu")
		(net "M_D_CPU0_CLK_DN<1>")
	)
	(segment
		(start 286.928306 -256.17424)
		(end 286.416496 -255.66243)
		(width 0.18288)
		(layer "In11.Cu")
		(net "M_D_CPU0_CLK_DN<1>")
	)
	(segment
		(start 305.730402 -255.445514)
		(end 304.984404 -256.191512)
		(width 0.18288)
		(layer "In11.Cu")
		(net "M_D_CPU0_CLK_DN<1>")
	)
	(segment
		(start 329.582272 -252.92177)
		(end 327.595738 -254.908558)
		(width 0.18288)
		(layer "In11.Cu")
		(net "M_D_CPU0_CLK_DN<1>")
	)
	(segment
		(start 327.595738 -254.908558)
		(end 323.984112 -254.908558)
		(width 0.18288)
		(layer "In11.Cu")
		(net "M_D_CPU0_CLK_DN<1>")
	)
	(segment
		(start 346.58173 -252.103128)
		(end 334.32242 -252.103128)
		(width 0.18288)
		(layer "In11.Cu")
		(net "M_D_CPU0_CLK_DN<1>")
	)
	(segment
		(start 294.4495 -256.087372)
		(end 294.053514 -255.691386)
		(width 0.18288)
		(layer "In11.Cu")
		(net "M_D_CPU0_CLK_DN<1>")
	)
	(segment
		(start 317.826136 -253.749302)
		(end 317.704216 -253.871222)
		(width 0.18288)
		(layer "In11.Cu")
		(net "M_D_CPU0_CLK_DN<1>")
	)
	(segment
		(start 274.530566 -256.234946)
		(end 271.290542 -256.234946)
		(width 0.18288)
		(layer "In11.Cu")
		(net "M_D_CPU0_CLK_DN<1>")
	)
	(segment
		(start 320.447416 -253.749302)
		(end 320.325496 -253.871222)
		(width 0.18288)
		(layer "In11.Cu")
		(net "M_D_CPU0_CLK_DN<1>")
	)
	(segment
		(start 308.703472 -255.323594)
		(end 308.170072 -255.323594)
		(width 0.18288)
		(layer "In11.Cu")
		(net "M_D_CPU0_CLK_DN<1>")
	)
	(segment
		(start 318.481456 -253.871222)
		(end 318.359536 -253.749302)
		(width 0.18288)
		(layer "In11.Cu")
		(net "M_D_CPU0_CLK_DN<1>")
	)
	(segment
		(start 317.170816 -253.871222)
		(end 317.048896 -253.749302)
		(width 0.18288)
		(layer "In11.Cu")
		(net "M_D_CPU0_CLK_DN<1>")
	)
	(segment
		(start 271.290542 -256.234946)
		(end 269.303754 -258.221734)
		(width 0.18288)
		(layer "In11.Cu")
		(net "M_D_CPU0_CLK_DN<1>")
	)
	(segment
		(start 314.485274 -254.081026)
		(end 313.99226 -254.285242)
		(width 0.18288)
		(layer "In11.Cu")
		(net "M_D_CPU0_CLK_DN<1>")
	)
	(segment
		(start 348.167198 -250.51766)
		(end 346.58173 -252.103128)
		(width 0.18288)
		(layer "In11.Cu")
		(net "M_D_CPU0_CLK_DN<1>")
	)
	(segment
		(start 312.451242 -254.924306)
		(end 312.385202 -255.083818)
		(width 0.18288)
		(layer "In11.Cu")
		(net "M_D_CPU0_CLK_DN<1>")
	)
	(segment
		(start 321.636136 -253.871222)
		(end 321.102736 -253.871222)
		(width 0.18288)
		(layer "In11.Cu")
		(net "M_D_CPU0_CLK_DN<1>")
	)
	(segment
		(start 310.014112 -255.323594)
		(end 309.480712 -255.323594)
		(width 0.18288)
		(layer "In11.Cu")
		(net "M_D_CPU0_CLK_DN<1>")
	)
	(segment
		(start 320.980816 -253.749302)
		(end 320.447416 -253.749302)
		(width 0.18288)
		(layer "In11.Cu")
		(net "M_D_CPU0_CLK_DN<1>")
	)
	(segment
		(start 321.758056 -253.749302)
		(end 321.636136 -253.871222)
		(width 0.18288)
		(layer "In11.Cu")
		(net "M_D_CPU0_CLK_DN<1>")
	)
	(segment
		(start 269.303754 -258.221734)
		(end 269.303754 -259.17779)
		(width 0.18288)
		(layer "In11.Cu")
		(net "M_D_CPU0_CLK_DN<1>")
	)
	(segment
		(start 322.413376 -253.871222)
		(end 322.291456 -253.749302)
		(width 0.18288)
		(layer "In11.Cu")
		(net "M_D_CPU0_CLK_DN<1>")
	)
	(segment
		(start 282.218892 -256.117852)
		(end 279.325578 -256.117852)
		(width 0.18288)
		(layer "In11.Cu")
		(net "M_D_CPU0_CLK_DN<1>")
	)
	(segment
		(start 348.167198 -249.954542)
		(end 348.167198 -250.51766)
		(width 0.18288)
		(layer "In11.Cu")
		(net "M_D_CPU0_CLK_DN<1>")
	)
	(segment
		(start 297.596814 -255.748028)
		(end 297.25747 -256.087372)
		(width 0.18288)
		(layer "In11.Cu")
		(net "M_D_CPU0_CLK_DN<1>")
	)
	(segment
		(start 347.83268 -249.620024)
		(end 348.167198 -249.954542)
		(width 0.18288)
		(layer "In11.Cu")
		(net "M_D_CPU0_CLK_DN<1>")
	)
	(segment
		(start 308.170072 -255.323594)
		(end 308.048152 -255.445514)
		(width 0.18288)
		(layer "In11.Cu")
		(net "M_D_CPU0_CLK_DN<1>")
	)
	(segment
		(start 312.944256 -254.72009)
		(end 312.451242 -254.924306)
		(width 0.18288)
		(layer "In11.Cu")
		(net "M_D_CPU0_CLK_DN<1>")
	)
	(segment
		(start 278.945848 -255.738122)
		(end 275.02739 -255.738122)
		(width 0.18288)
		(layer "In11.Cu")
		(net "M_D_CPU0_CLK_DN<1>")
	)
	(segment
		(start 311.512966 -255.445514)
		(end 310.136032 -255.445514)
		(width 0.18288)
		(layer "In11.Cu")
		(net "M_D_CPU0_CLK_DN<1>")
	)
	(segment
		(start 321.102736 -253.871222)
		(end 320.980816 -253.749302)
		(width 0.18288)
		(layer "In11.Cu")
		(net "M_D_CPU0_CLK_DN<1>")
	)
	(segment
		(start 289.649408 -256.17424)
		(end 286.928306 -256.17424)
		(width 0.18288)
		(layer "In11.Cu")
		(net "M_D_CPU0_CLK_DN<1>")
	)
	(segment
		(start 320.325496 -253.871222)
		(end 319.792096 -253.871222)
		(width 0.18288)
		(layer "In11.Cu")
		(net "M_D_CPU0_CLK_DN<1>")
	)
	(segment
		(start 279.325578 -256.117852)
		(end 278.945848 -255.738122)
		(width 0.18288)
		(layer "In11.Cu")
		(net "M_D_CPU0_CLK_DN<1>")
	)
	(segment
		(start 310.136032 -255.445514)
		(end 310.014112 -255.323594)
		(width 0.18288)
		(layer "In11.Cu")
		(net "M_D_CPU0_CLK_DN<1>")
	)
	(segment
		(start 308.825392 -255.445514)
		(end 308.703472 -255.323594)
		(width 0.18288)
		(layer "In11.Cu")
		(net "M_D_CPU0_CLK_DN<1>")
	)
	(segment
		(start 334.066642 -252.358906)
		(end 330.94168 -252.358906)
		(width 0.18288)
		(layer "In11.Cu")
		(net "M_D_CPU0_CLK_DN<1>")
	)
	(segment
		(start 275.02739 -255.738122)
		(end 274.530566 -256.234946)
		(width 0.18288)
		(layer "In11.Cu")
		(net "M_D_CPU0_CLK_DN<1>")
	)
	(segment
		(start 316.515496 -253.749302)
		(end 316.393576 -253.871222)
		(width 0.18288)
		(layer "In11.Cu")
		(net "M_D_CPU0_CLK_DN<1>")
	)
	(segment
		(start 316.393576 -253.871222)
		(end 315.310012 -253.871222)
		(width 0.18288)
		(layer "In11.Cu")
		(net "M_D_CPU0_CLK_DN<1>")
	)
	(segment
		(start 319.136776 -253.749302)
		(end 319.014856 -253.871222)
		(width 0.18288)
		(layer "In11.Cu")
		(net "M_D_CPU0_CLK_DN<1>")
	)
	(segment
		(start 318.359536 -253.749302)
		(end 317.826136 -253.749302)
		(width 0.18288)
		(layer "In11.Cu")
		(net "M_D_CPU0_CLK_DN<1>")
	)
	(segment
		(start 322.291456 -253.749302)
		(end 321.758056 -253.749302)
		(width 0.18288)
		(layer "In11.Cu")
		(net "M_D_CPU0_CLK_DN<1>")
	)
	(segment
		(start 269.11554 -259.366004)
		(end 268.830044 -259.366004)
		(width 0.18288)
		(layer "In11.Cu")
		(net "M_D_CPU0_CLK_DN<1>")
	)
	(segment
		(start 304.984404 -256.191512)
		(end 301.865538 -256.191512)
		(width 0.18288)
		(layer "In11.Cu")
		(net "M_D_CPU0_CLK_DN<1>")
	)
	(segment
		(start 317.048896 -253.749302)
		(end 316.515496 -253.749302)
		(width 0.18288)
		(layer "In11.Cu")
		(net "M_D_CPU0_CLK_DN<1>")
	)
	(segment
		(start 282.674314 -255.66243)
		(end 282.218892 -256.117852)
		(width 0.18288)
		(layer "In11.Cu")
		(net "M_D_CPU0_CLK_DN<1>")
	)
	(segment
		(start 286.416496 -255.66243)
		(end 282.674314 -255.66243)
		(width 0.18288)
		(layer "In11.Cu")
		(net "M_D_CPU0_CLK_DN<1>")
	)
	(segment
		(start 315.310012 -253.871222)
		(end 314.644532 -254.147066)
		(width 0.18288)
		(layer "In11.Cu")
		(net "M_D_CPU0_CLK_DN<1>")
	)
	(segment
		(start 309.480712 -255.323594)
		(end 309.358792 -255.445514)
		(width 0.18288)
		(layer "In11.Cu")
		(net "M_D_CPU0_CLK_DN<1>")
	)
	(segment
		(start 301.422054 -255.748028)
		(end 297.596814 -255.748028)
		(width 0.18288)
		(layer "In11.Cu")
		(net "M_D_CPU0_CLK_DN<1>")
	)
	(segment
		(start 314.644532 -254.147066)
		(end 314.485274 -254.081026)
		(width 0.18288)
		(layer "In11.Cu")
		(net "M_D_CPU0_CLK_DN<1>")
	)
	(segment
		(start 294.053514 -255.691386)
		(end 290.132262 -255.691386)
		(width 0.18288)
		(layer "In11.Cu")
		(net "M_D_CPU0_CLK_DN<1>")
	)
	(segment
		(start 261.285482 -259.366766)
		(end 260.180582 -259.366766)
		(width 0.20066)
		(layer "F.Cu")
		(net "M_D_CPU0_CLK_DN<0>")
	)
	(segment
		(start 345.953334 -249.620278)
		(end 345.95308 -249.620024)
		(width 0.20066)
		(layer "F.Cu")
		(net "M_D_CPU0_CLK_DN<0>")
	)
	(segment
		(start 345.953334 -250.155964)
		(end 345.953334 -249.620278)
		(width 0.20066)
		(layer "F.Cu")
		(net "M_D_CPU0_CLK_DN<0>")
	)
	(segment
		(start 311.899808 -251.794772)
		(end 311.109868 -251.794772)
		(width 0.18288)
		(layer "In11.Cu")
		(net "M_D_CPU0_CLK_DN<0>")
	)
	(segment
		(start 309.661052 -252.460506)
		(end 309.499254 -252.400816)
		(width 0.18288)
		(layer "In11.Cu")
		(net "M_D_CPU0_CLK_DN<0>")
	)
	(segment
		(start 296.909744 -255.259078)
		(end 294.810688 -255.259078)
		(width 0.18288)
		(layer "In11.Cu")
		(net "M_D_CPU0_CLK_DN<0>")
	)
	(segment
		(start 345.95308 -249.620024)
		(end 345.967812 -249.620024)
		(width 0.18288)
		(layer "In11.Cu")
		(net "M_D_CPU0_CLK_DN<0>")
	)
	(segment
		(start 345.967812 -249.620024)
		(end 346.275406 -249.927618)
		(width 0.18288)
		(layer "In11.Cu")
		(net "M_D_CPU0_CLK_DN<0>")
	)
	(segment
		(start 289.297618 -255.320546)
		(end 287.255966 -255.320546)
		(width 0.18288)
		(layer "In11.Cu")
		(net "M_D_CPU0_CLK_DN<0>")
	)
	(segment
		(start 308.954424 -252.785372)
		(end 308.316122 -253.078742)
		(width 0.18288)
		(layer "In11.Cu")
		(net "M_D_CPU0_CLK_DN<0>")
	)
	(segment
		(start 316.695836 -252.63221)
		(end 315.985906 -252.63221)
		(width 0.18288)
		(layer "In11.Cu")
		(net "M_D_CPU0_CLK_DN<0>")
	)
	(segment
		(start 317.351156 -252.51029)
		(end 316.817756 -252.51029)
		(width 0.18288)
		(layer "In11.Cu")
		(net "M_D_CPU0_CLK_DN<0>")
	)
	(segment
		(start 262.725154 -259.251196)
		(end 261.769352 -259.648198)
		(width 0.18288)
		(layer "In11.Cu")
		(net "M_D_CPU0_CLK_DN<0>")
	)
	(segment
		(start 301.780194 -254.919988)
		(end 297.248834 -254.919988)
		(width 0.18288)
		(layer "In11.Cu")
		(net "M_D_CPU0_CLK_DN<0>")
	)
	(segment
		(start 314.607194 -252.225048)
		(end 314.084208 -252.11786)
		(width 0.18288)
		(layer "In11.Cu")
		(net "M_D_CPU0_CLK_DN<0>")
	)
	(segment
		(start 289.757866 -254.860298)
		(end 289.297618 -255.320546)
		(width 0.18288)
		(layer "In11.Cu")
		(net "M_D_CPU0_CLK_DN<0>")
	)
	(segment
		(start 307.669438 -253.242064)
		(end 307.609748 -253.403608)
		(width 0.18288)
		(layer "In11.Cu")
		(net "M_D_CPU0_CLK_DN<0>")
	)
	(segment
		(start 307.125116 -253.626366)
		(end 305.733196 -253.626366)
		(width 0.18288)
		(layer "In11.Cu")
		(net "M_D_CPU0_CLK_DN<0>")
	)
	(segment
		(start 297.248834 -254.919988)
		(end 296.909744 -255.259078)
		(width 0.18288)
		(layer "In11.Cu")
		(net "M_D_CPU0_CLK_DN<0>")
	)
	(segment
		(start 264.145522 -257.830828)
		(end 262.725154 -259.251196)
		(width 0.18288)
		(layer "In11.Cu")
		(net "M_D_CPU0_CLK_DN<0>")
	)
	(segment
		(start 294.411908 -254.860298)
		(end 289.757866 -254.860298)
		(width 0.18288)
		(layer "In11.Cu")
		(net "M_D_CPU0_CLK_DN<0>")
	)
	(segment
		(start 313.378342 -252.097794)
		(end 313.283346 -251.953776)
		(width 0.18288)
		(layer "In11.Cu")
		(net "M_D_CPU0_CLK_DN<0>")
	)
	(segment
		(start 304.572162 -255.320546)
		(end 302.180752 -255.320546)
		(width 0.18288)
		(layer "In11.Cu")
		(net "M_D_CPU0_CLK_DN<0>")
	)
	(segment
		(start 312.760614 -251.846588)
		(end 312.616596 -251.941584)
		(width 0.18288)
		(layer "In11.Cu")
		(net "M_D_CPU0_CLK_DN<0>")
	)
	(segment
		(start 264.710926 -257.59664)
		(end 264.145522 -257.830828)
		(width 0.18288)
		(layer "In11.Cu")
		(net "M_D_CPU0_CLK_DN<0>")
	)
	(segment
		(start 313.283346 -251.953776)
		(end 312.760614 -251.846588)
		(width 0.18288)
		(layer "In11.Cu")
		(net "M_D_CPU0_CLK_DN<0>")
	)
	(segment
		(start 279.676098 -255.288542)
		(end 279.068784 -254.681228)
		(width 0.18288)
		(layer "In11.Cu")
		(net "M_D_CPU0_CLK_DN<0>")
	)
	(segment
		(start 314.084208 -252.11786)
		(end 313.940444 -252.212856)
		(width 0.18288)
		(layer "In11.Cu")
		(net "M_D_CPU0_CLK_DN<0>")
	)
	(segment
		(start 307.609748 -253.403608)
		(end 307.125116 -253.626366)
		(width 0.18288)
		(layer "In11.Cu")
		(net "M_D_CPU0_CLK_DN<0>")
	)
	(segment
		(start 305.127914 -254.764794)
		(end 304.572162 -255.320546)
		(width 0.18288)
		(layer "In11.Cu")
		(net "M_D_CPU0_CLK_DN<0>")
	)
	(segment
		(start 287.255966 -255.320546)
		(end 286.59963 -254.66421)
		(width 0.18288)
		(layer "In11.Cu")
		(net "M_D_CPU0_CLK_DN<0>")
	)
	(segment
		(start 305.127914 -254.231648)
		(end 305.127914 -254.764794)
		(width 0.18288)
		(layer "In11.Cu")
		(net "M_D_CPU0_CLK_DN<0>")
	)
	(segment
		(start 316.817756 -252.51029)
		(end 316.695836 -252.63221)
		(width 0.18288)
		(layer "In11.Cu")
		(net "M_D_CPU0_CLK_DN<0>")
	)
	(segment
		(start 333.84617 -251.234956)
		(end 333.61122 -251.469906)
		(width 0.18288)
		(layer "In11.Cu")
		(net "M_D_CPU0_CLK_DN<0>")
	)
	(segment
		(start 279.068784 -254.681228)
		(end 274.89404 -254.681228)
		(width 0.18288)
		(layer "In11.Cu")
		(net "M_D_CPU0_CLK_DN<0>")
	)
	(segment
		(start 346.275406 -249.927618)
		(end 346.275406 -250.574302)
		(width 0.18288)
		(layer "In11.Cu")
		(net "M_D_CPU0_CLK_DN<0>")
	)
	(segment
		(start 305.733196 -253.626366)
		(end 305.127914 -254.231648)
		(width 0.18288)
		(layer "In11.Cu")
		(net "M_D_CPU0_CLK_DN<0>")
	)
	(segment
		(start 311.109868 -251.794772)
		(end 309.661052 -252.460506)
		(width 0.18288)
		(layer "In11.Cu")
		(net "M_D_CPU0_CLK_DN<0>")
	)
	(segment
		(start 274.178522 -255.396746)
		(end 270.241268 -255.396746)
		(width 0.18288)
		(layer "In11.Cu")
		(net "M_D_CPU0_CLK_DN<0>")
	)
	(segment
		(start 327.178924 -254.235712)
		(end 324.542912 -254.235712)
		(width 0.18288)
		(layer "In11.Cu")
		(net "M_D_CPU0_CLK_DN<0>")
	)
	(segment
		(start 294.810688 -255.259078)
		(end 294.411908 -254.860298)
		(width 0.18288)
		(layer "In11.Cu")
		(net "M_D_CPU0_CLK_DN<0>")
	)
	(segment
		(start 261.769352 -259.648198)
		(end 261.566914 -259.648198)
		(width 0.18288)
		(layer "In11.Cu")
		(net "M_D_CPU0_CLK_DN<0>")
	)
	(segment
		(start 314.701936 -252.369066)
		(end 314.607194 -252.225048)
		(width 0.18288)
		(layer "In11.Cu")
		(net "M_D_CPU0_CLK_DN<0>")
	)
	(segment
		(start 346.275406 -250.574302)
		(end 345.614752 -251.234956)
		(width 0.18288)
		(layer "In11.Cu")
		(net "M_D_CPU0_CLK_DN<0>")
	)
	(segment
		(start 270.241268 -255.396746)
		(end 268.041374 -257.59664)
		(width 0.18288)
		(layer "In11.Cu")
		(net "M_D_CPU0_CLK_DN<0>")
	)
	(segment
		(start 281.850846 -255.288542)
		(end 279.676098 -255.288542)
		(width 0.18288)
		(layer "In11.Cu")
		(net "M_D_CPU0_CLK_DN<0>")
	)
	(segment
		(start 345.614752 -251.234956)
		(end 333.84617 -251.234956)
		(width 0.18288)
		(layer "In11.Cu")
		(net "M_D_CPU0_CLK_DN<0>")
	)
	(segment
		(start 308.316122 -253.078742)
		(end 308.154324 -253.019052)
		(width 0.18288)
		(layer "In11.Cu")
		(net "M_D_CPU0_CLK_DN<0>")
	)
	(segment
		(start 313.940444 -252.212856)
		(end 313.378342 -252.097794)
		(width 0.18288)
		(layer "In11.Cu")
		(net "M_D_CPU0_CLK_DN<0>")
	)
	(segment
		(start 329.94473 -251.469906)
		(end 327.178924 -254.235712)
		(width 0.18288)
		(layer "In11.Cu")
		(net "M_D_CPU0_CLK_DN<0>")
	)
	(segment
		(start 312.616596 -251.941584)
		(end 311.899808 -251.794772)
		(width 0.18288)
		(layer "In11.Cu")
		(net "M_D_CPU0_CLK_DN<0>")
	)
	(segment
		(start 302.180752 -255.320546)
		(end 301.780194 -254.919988)
		(width 0.18288)
		(layer "In11.Cu")
		(net "M_D_CPU0_CLK_DN<0>")
	)
	(segment
		(start 315.985906 -252.63221)
		(end 314.701936 -252.369066)
		(width 0.18288)
		(layer "In11.Cu")
		(net "M_D_CPU0_CLK_DN<0>")
	)
	(segment
		(start 261.566914 -259.648198)
		(end 261.285482 -259.366766)
		(width 0.18288)
		(layer "In11.Cu")
		(net "M_D_CPU0_CLK_DN<0>")
	)
	(segment
		(start 309.499254 -252.400816)
		(end 309.014368 -252.623828)
		(width 0.18288)
		(layer "In11.Cu")
		(net "M_D_CPU0_CLK_DN<0>")
	)
	(segment
		(start 317.473076 -252.63221)
		(end 317.351156 -252.51029)
		(width 0.18288)
		(layer "In11.Cu")
		(net "M_D_CPU0_CLK_DN<0>")
	)
	(segment
		(start 333.61122 -251.469906)
		(end 329.94473 -251.469906)
		(width 0.18288)
		(layer "In11.Cu")
		(net "M_D_CPU0_CLK_DN<0>")
	)
	(segment
		(start 274.89404 -254.681228)
		(end 274.178522 -255.396746)
		(width 0.18288)
		(layer "In11.Cu")
		(net "M_D_CPU0_CLK_DN<0>")
	)
	(segment
		(start 324.542912 -254.235712)
		(end 322.93941 -252.63221)
		(width 0.18288)
		(layer "In11.Cu")
		(net "M_D_CPU0_CLK_DN<0>")
	)
	(segment
		(start 308.154324 -253.019052)
		(end 307.669438 -253.242064)
		(width 0.18288)
		(layer "In11.Cu")
		(net "M_D_CPU0_CLK_DN<0>")
	)
	(segment
		(start 322.93941 -252.63221)
		(end 317.473076 -252.63221)
		(width 0.18288)
		(layer "In11.Cu")
		(net "M_D_CPU0_CLK_DN<0>")
	)
	(segment
		(start 309.014368 -252.623828)
		(end 308.954424 -252.785372)
		(width 0.18288)
		(layer "In11.Cu")
		(net "M_D_CPU0_CLK_DN<0>")
	)
	(segment
		(start 282.475178 -254.66421)
		(end 281.850846 -255.288542)
		(width 0.18288)
		(layer "In11.Cu")
		(net "M_D_CPU0_CLK_DN<0>")
	)
	(segment
		(start 286.59963 -254.66421)
		(end 282.475178 -254.66421)
		(width 0.18288)
		(layer "In11.Cu")
		(net "M_D_CPU0_CLK_DN<0>")
	)
	(segment
		(start 268.041374 -257.59664)
		(end 264.710926 -257.59664)
		(width 0.18288)
		(layer "In11.Cu")
		(net "M_D_CPU0_CLK_DN<0>")
	)
	(segment
		(start 258.28498 -269.62354)
		(end 258.130548 -269.777972)
		(width 0.20066)
		(layer "F.Cu")
		(net "M_D_CPU0_ALERT_N")
	)
	(segment
		(start 259.056378 -269.132812)
		(end 258.44754 -269.132812)
		(width 0.20066)
		(layer "F.Cu")
		(net "M_D_CPU0_ALERT_N")
	)
	(segment
		(start 258.130548 -269.777972)
		(end 257.626104 -269.777972)
		(width 0.20066)
		(layer "F.Cu")
		(net "M_D_CPU0_ALERT_N")
	)
	(segment
		(start 258.44754 -269.132812)
		(end 258.28498 -269.295372)
		(width 0.20066)
		(layer "F.Cu")
		(net "M_D_CPU0_ALERT_N")
	)
	(segment
		(start 259.065268 -269.141702)
		(end 259.056378 -269.132812)
		(width 0.1016)
		(layer "F.Cu")
		(net "M_D_CPU0_ALERT_N")
	)
	(segment
		(start 261.381494 -269.141702)
		(end 261.350252 -269.141702)
		(width 0.101854)
		(layer "F.Cu")
		(net "M_D_CPU0_ALERT_N")
	)
	(segment
		(start 350.292162 -253.383796)
		(end 350.292162 -253.919482)
		(width 0.20066)
		(layer "F.Cu")
		(net "M_D_CPU0_ALERT_N")
	)
	(segment
		(start 263.624314 -269.566644)
		(end 262.010398 -269.566644)
		(width 0.20066)
		(layer "F.Cu")
		(net "M_D_CPU0_ALERT_N")
	)
	(segment
		(start 261.585456 -269.141702)
		(end 261.381494 -269.141702)
		(width 0.20066)
		(layer "F.Cu")
		(net "M_D_CPU0_ALERT_N")
	)
	(segment
		(start 258.28498 -269.295372)
		(end 258.28498 -269.62354)
		(width 0.20066)
		(layer "F.Cu")
		(net "M_D_CPU0_ALERT_N")
	)
	(segment
		(start 261.350252 -269.141702)
		(end 259.065268 -269.141702)
		(width 0.1016)
		(layer "F.Cu")
		(net "M_D_CPU0_ALERT_N")
	)
	(segment
		(start 264.729214 -269.566644)
		(end 263.624314 -269.566644)
		(width 0.20066)
		(layer "F.Cu")
		(net "M_D_CPU0_ALERT_N")
	)
	(segment
		(start 350.292162 -253.919482)
		(end 350.292416 -253.919736)
		(width 0.20066)
		(layer "F.Cu")
		(net "M_D_CPU0_ALERT_N")
	)
	(segment
		(start 257.414776 -269.566644)
		(end 256.080514 -269.566644)
		(width 0.20066)
		(layer "F.Cu")
		(net "M_D_CPU0_ALERT_N")
	)
	(segment
		(start 262.010398 -269.566644)
		(end 261.585456 -269.141702)
		(width 0.20066)
		(layer "F.Cu")
		(net "M_D_CPU0_ALERT_N")
	)
	(segment
		(start 257.626104 -269.777972)
		(end 257.414776 -269.566644)
		(width 0.20066)
		(layer "F.Cu")
		(net "M_D_CPU0_ALERT_N")
	)
	(via
		(at 264.729214 -269.566644)
		(size 0.4572)
		(drill 0.2032)
		(layers "F.Cu" "B.Cu")
		(net "M_D_CPU0_ALERT_N")
	)
	(via
		(at 350.292416 -253.919736)
		(size 0.4572)
		(drill 0.2032)
		(layers "F.Cu" "B.Cu")
		(net "M_D_CPU0_ALERT_N")
	)
	(segment
		(start 291.92601 -266.593574)
		(end 289.884358 -266.593574)
		(width 0.18288)
		(layer "In11.Cu")
		(net "M_D_CPU0_ALERT_N")
	)
	(segment
		(start 310.643524 -265.752326)
		(end 309.003192 -265.752326)
		(width 0.18288)
		(layer "In11.Cu")
		(net "M_D_CPU0_ALERT_N")
	)
	(segment
		(start 344.431874 -260.01599)
		(end 344.418412 -260.023864)
		(width 0.18288)
		(layer "In11.Cu")
		(net "M_D_CPU0_ALERT_N")
	)
	(segment
		(start 288.097214 -266.469876)
		(end 284.60446 -266.469876)
		(width 0.18288)
		(layer "In11.Cu")
		(net "M_D_CPU0_ALERT_N")
	)
	(segment
		(start 314.423044 -263.826752)
		(end 313.907932 -263.826752)
		(width 0.18288)
		(layer "In11.Cu")
		(net "M_D_CPU0_ALERT_N")
	)
	(segment
		(start 275.143468 -267.417042)
		(end 273.791426 -267.417042)
		(width 0.18288)
		(layer "In11.Cu")
		(net "M_D_CPU0_ALERT_N")
	)
	(segment
		(start 348.65818 -259.203698)
		(end 348.647512 -259.210048)
		(width 0.088646)
		(layer "In11.Cu")
		(net "M_D_CPU0_ALERT_N")
	)
	(segment
		(start 338.309712 -260.023864)
		(end 338.29625 -260.01599)
		(width 0.18288)
		(layer "In11.Cu")
		(net "M_D_CPU0_ALERT_N")
	)
	(segment
		(start 311.471564 -264.924286)
		(end 310.643524 -265.752326)
		(width 0.18288)
		(layer "In11.Cu")
		(net "M_D_CPU0_ALERT_N")
	)
	(segment
		(start 273.791426 -267.417042)
		(end 272.916142 -268.292326)
		(width 0.18288)
		(layer "In11.Cu")
		(net "M_D_CPU0_ALERT_N")
	)
	(segment
		(start 284.48127 -266.593066)
		(end 283.12364 -266.593066)
		(width 0.18288)
		(layer "In11.Cu")
		(net "M_D_CPU0_ALERT_N")
	)
	(segment
		(start 265.962384 -268.95806)
		(end 265.3538 -269.566644)
		(width 0.18288)
		(layer "In11.Cu")
		(net "M_D_CPU0_ALERT_N")
	)
	(segment
		(start 281.020774 -267.275056)
		(end 280.337006 -266.591288)
		(width 0.18288)
		(layer "In11.Cu")
		(net "M_D_CPU0_ALERT_N")
	)
	(segment
		(start 296.573448 -266.69492)
		(end 296.470832 -266.592304)
		(width 0.18288)
		(layer "In11.Cu")
		(net "M_D_CPU0_ALERT_N")
	)
	(segment
		(start 345.570302 -260.050026)
		(end 345.123262 -260.050026)
		(width 0.088646)
		(layer "In11.Cu")
		(net "M_D_CPU0_ALERT_N")
	)
	(segment
		(start 349.352362 -257.98907)
		(end 349.352362 -258.002532)
		(width 0.088646)
		(layer "In11.Cu")
		(net "M_D_CPU0_ALERT_N")
	)
	(segment
		(start 337.369912 -260.023864)
		(end 337.35645 -260.01599)
		(width 0.18288)
		(layer "In11.Cu")
		(net "M_D_CPU0_ALERT_N")
	)
	(segment
		(start 270.51127 -269.727426)
		(end 269.644114 -269.727426)
		(width 0.18288)
		(layer "In11.Cu")
		(net "M_D_CPU0_ALERT_N")
	)
	(segment
		(start 348.182438 -260.02107)
		(end 348.177612 -260.023864)
		(width 0.088646)
		(layer "In11.Cu")
		(net "M_D_CPU0_ALERT_N")
	)
	(segment
		(start 277.22449 -266.427204)
		(end 277.061168 -266.590526)
		(width 0.18288)
		(layer "In11.Cu")
		(net "M_D_CPU0_ALERT_N")
	)
	(segment
		(start 348.882716 -257.175254)
		(end 348.882716 -257.184906)
		(width 0.088646)
		(layer "In11.Cu")
		(net "M_D_CPU0_ALERT_N")
	)
	(segment
		(start 350.292416 -253.919736)
		(end 350.270064 -254.808482)
		(width 0.088646)
		(layer "In11.Cu")
		(net "M_D_CPU0_ALERT_N")
	)
	(segment
		(start 321.723766 -259.75691)
		(end 319.938146 -261.54253)
		(width 0.18288)
		(layer "In11.Cu")
		(net "M_D_CPU0_ALERT_N")
	)
	(segment
		(start 309.003192 -265.752326)
		(end 308.96179 -265.793728)
		(width 0.18288)
		(layer "In11.Cu")
		(net "M_D_CPU0_ALERT_N")
	)
	(segment
		(start 296.470832 -266.592304)
		(end 293.142416 -266.592304)
		(width 0.18288)
		(layer "In11.Cu")
		(net "M_D_CPU0_ALERT_N")
	)
	(segment
		(start 342.068912 -260.023864)
		(end 342.05545 -260.01599)
		(width 0.18288)
		(layer "In11.Cu")
		(net "M_D_CPU0_ALERT_N")
	)
	(segment
		(start 288.3535 -266.726162)
		(end 288.097214 -266.469876)
		(width 0.18288)
		(layer "In11.Cu")
		(net "M_D_CPU0_ALERT_N")
	)
	(segment
		(start 292.085014 -266.43457)
		(end 291.92601 -266.593574)
		(width 0.18288)
		(layer "In11.Cu")
		(net "M_D_CPU0_ALERT_N")
	)
	(segment
		(start 349.59798 -255.94818)
		(end 349.587312 -255.95453)
		(width 0.088646)
		(layer "In11.Cu")
		(net "M_D_CPU0_ALERT_N")
	)
	(segment
		(start 349.352616 -256.34696)
		(end 349.352616 -256.361438)
		(width 0.088646)
		(layer "In11.Cu")
		(net "M_D_CPU0_ALERT_N")
	)
	(segment
		(start 349.822516 -255.53035)
		(end 349.822516 -255.547622)
		(width 0.088646)
		(layer "In11.Cu")
		(net "M_D_CPU0_ALERT_N")
	)
	(segment
		(start 297.00093 -266.69492)
		(end 296.573448 -266.69492)
		(width 0.18288)
		(layer "In11.Cu")
		(net "M_D_CPU0_ALERT_N")
	)
	(segment
		(start 349.122492 -256.765552)
		(end 349.11284 -256.77114)
		(width 0.088646)
		(layer "In11.Cu")
		(net "M_D_CPU0_ALERT_N")
	)
	(segment
		(start 284.60446 -266.469876)
		(end 284.48127 -266.593066)
		(width 0.18288)
		(layer "In11.Cu")
		(net "M_D_CPU0_ALERT_N")
	)
	(segment
		(start 342.552274 -260.01599)
		(end 342.538812 -260.023864)
		(width 0.18288)
		(layer "In11.Cu")
		(net "M_D_CPU0_ALERT_N")
	)
	(segment
		(start 348.882716 -258.788662)
		(end 348.882716 -258.80314)
		(width 0.088646)
		(layer "In11.Cu")
		(net "M_D_CPU0_ALERT_N")
	)
	(segment
		(start 277.061168 -266.590526)
		(end 275.969984 -266.590526)
		(width 0.18288)
		(layer "In11.Cu")
		(net "M_D_CPU0_ALERT_N")
	)
	(segment
		(start 306.966874 -265.680444)
		(end 304.038762 -265.680444)
		(width 0.18288)
		(layer "In11.Cu")
		(net "M_D_CPU0_ALERT_N")
	)
	(segment
		(start 292.984682 -266.43457)
		(end 292.085014 -266.43457)
		(width 0.18288)
		(layer "In11.Cu")
		(net "M_D_CPU0_ALERT_N")
	)
	(segment
		(start 332.0542 -259.9563)
		(end 331.85481 -259.75691)
		(width 0.18288)
		(layer "In11.Cu")
		(net "M_D_CPU0_ALERT_N")
	)
	(segment
		(start 346.730574 -260.11251)
		(end 346.72016 -260.106414)
		(width 0.088646)
		(layer "In11.Cu")
		(net "M_D_CPU0_ALERT_N")
	)
	(segment
		(start 333.610712 -260.023864)
		(end 333.03083 -260.023864)
		(width 0.18288)
		(layer "In11.Cu")
		(net "M_D_CPU0_ALERT_N")
	)
	(segment
		(start 346.345764 -260.106414)
		(end 346.33535 -260.11251)
		(width 0.088646)
		(layer "In11.Cu")
		(net "M_D_CPU0_ALERT_N")
	)
	(segment
		(start 319.938146 -261.54253)
		(end 314.423044 -263.826752)
		(width 0.18288)
		(layer "In11.Cu")
		(net "M_D_CPU0_ALERT_N")
	)
	(segment
		(start 307.080158 -265.793728)
		(end 306.966874 -265.680444)
		(width 0.18288)
		(layer "In11.Cu")
		(net "M_D_CPU0_ALERT_N")
	)
	(segment
		(start 304.038762 -265.680444)
		(end 303.31918 -266.400026)
		(width 0.18288)
		(layer "In11.Cu")
		(net "M_D_CPU0_ALERT_N")
	)
	(segment
		(start 339.719412 -260.023864)
		(end 339.70976 -260.029452)
		(width 0.18288)
		(layer "In11.Cu")
		(net "M_D_CPU0_ALERT_N")
	)
	(segment
		(start 278.11476 -266.427204)
		(end 277.22449 -266.427204)
		(width 0.18288)
		(layer "In11.Cu")
		(net "M_D_CPU0_ALERT_N")
	)
	(segment
		(start 313.907932 -263.826752)
		(end 312.810398 -264.924286)
		(width 0.18288)
		(layer "In11.Cu")
		(net "M_D_CPU0_ALERT_N")
	)
	(segment
		(start 299.277786 -266.591034)
		(end 297.104816 -266.591034)
		(width 0.18288)
		(layer "In11.Cu")
		(net "M_D_CPU0_ALERT_N")
	)
	(segment
		(start 350.270064 -254.808482)
		(end 350.154494 -255.065784)
		(width 0.088646)
		(layer "In11.Cu")
		(net "M_D_CPU0_ALERT_N")
	)
	(segment
		(start 275.969984 -266.590526)
		(end 275.143468 -267.417042)
		(width 0.18288)
		(layer "In11.Cu")
		(net "M_D_CPU0_ALERT_N")
	)
	(segment
		(start 268.874748 -268.95806)
		(end 265.962384 -268.95806)
		(width 0.18288)
		(layer "In11.Cu")
		(net "M_D_CPU0_ALERT_N")
	)
	(segment
		(start 293.142416 -266.592304)
		(end 292.984682 -266.43457)
		(width 0.18288)
		(layer "In11.Cu")
		(net "M_D_CPU0_ALERT_N")
	)
	(segment
		(start 308.96179 -265.793728)
		(end 307.080158 -265.793728)
		(width 0.18288)
		(layer "In11.Cu")
		(net "M_D_CPU0_ALERT_N")
	)
	(segment
		(start 349.117412 -257.582162)
		(end 349.122238 -257.584956)
		(width 0.088646)
		(layer "In11.Cu")
		(net "M_D_CPU0_ALERT_N")
	)
	(segment
		(start 265.3538 -269.566644)
		(end 264.729214 -269.566644)
		(width 0.18288)
		(layer "In11.Cu")
		(net "M_D_CPU0_ALERT_N")
	)
	(segment
		(start 269.644114 -269.727426)
		(end 268.874748 -268.95806)
		(width 0.18288)
		(layer "In11.Cu")
		(net "M_D_CPU0_ALERT_N")
	)
	(segment
		(start 289.75177 -266.726162)
		(end 288.3535 -266.726162)
		(width 0.18288)
		(layer "In11.Cu")
		(net "M_D_CPU0_ALERT_N")
	)
	(segment
		(start 341.129112 -260.023864)
		(end 341.11565 -260.01599)
		(width 0.18288)
		(layer "In11.Cu")
		(net "M_D_CPU0_ALERT_N")
	)
	(segment
		(start 332.963266 -259.9563)
		(end 332.0542 -259.9563)
		(width 0.18288)
		(layer "In11.Cu")
		(net "M_D_CPU0_ALERT_N")
	)
	(segment
		(start 312.810398 -264.924286)
		(end 311.471564 -264.924286)
		(width 0.18288)
		(layer "In11.Cu")
		(net "M_D_CPU0_ALERT_N")
	)
	(segment
		(start 271.94637 -268.292326)
		(end 270.51127 -269.727426)
		(width 0.18288)
		(layer "In11.Cu")
		(net "M_D_CPU0_ALERT_N")
	)
	(segment
		(start 331.85481 -259.75691)
		(end 321.723766 -259.75691)
		(width 0.18288)
		(layer "In11.Cu")
		(net "M_D_CPU0_ALERT_N")
	)
	(segment
		(start 333.03083 -260.023864)
		(end 332.963266 -259.9563)
		(width 0.18288)
		(layer "In11.Cu")
		(net "M_D_CPU0_ALERT_N")
	)
	(segment
		(start 348.177612 -260.023864)
		(end 348.034864 -260.10616)
		(width 0.088646)
		(layer "In11.Cu")
		(net "M_D_CPU0_ALERT_N")
	)
	(segment
		(start 278.278844 -266.591288)
		(end 278.11476 -266.427204)
		(width 0.18288)
		(layer "In11.Cu")
		(net "M_D_CPU0_ALERT_N")
	)
	(segment
		(start 345.123262 -260.050026)
		(end 344.985848 -260.050026)
		(width 0.18288)
		(layer "In11.Cu")
		(net "M_D_CPU0_ALERT_N")
	)
	(segment
		(start 297.104816 -266.591034)
		(end 297.00093 -266.69492)
		(width 0.18288)
		(layer "In11.Cu")
		(net "M_D_CPU0_ALERT_N")
	)
	(segment
		(start 339.249766 -260.023864)
		(end 339.240114 -260.018276)
		(width 0.18288)
		(layer "In11.Cu")
		(net "M_D_CPU0_ALERT_N")
	)
	(segment
		(start 299.468794 -266.400026)
		(end 299.277786 -266.591034)
		(width 0.18288)
		(layer "In11.Cu")
		(net "M_D_CPU0_ALERT_N")
	)
	(segment
		(start 272.916142 -268.292326)
		(end 271.94637 -268.292326)
		(width 0.18288)
		(layer "In11.Cu")
		(net "M_D_CPU0_ALERT_N")
	)
	(segment
		(start 303.31918 -266.400026)
		(end 299.468794 -266.400026)
		(width 0.18288)
		(layer "In11.Cu")
		(net "M_D_CPU0_ALERT_N")
	)
	(segment
		(start 343.948512 -260.023864)
		(end 343.93505 -260.01599)
		(width 0.18288)
		(layer "In11.Cu")
		(net "M_D_CPU0_ALERT_N")
	)
	(segment
		(start 283.12364 -266.593066)
		(end 282.44165 -267.275056)
		(width 0.18288)
		(layer "In11.Cu")
		(net "M_D_CPU0_ALERT_N")
	)
	(segment
		(start 348.647512 -259.210048)
		(end 348.642686 -259.212842)
		(width 0.088646)
		(layer "In11.Cu")
		(net "M_D_CPU0_ALERT_N")
	)
	(segment
		(start 289.884358 -266.593574)
		(end 289.75177 -266.726162)
		(width 0.18288)
		(layer "In11.Cu")
		(net "M_D_CPU0_ALERT_N")
	)
	(segment
		(start 280.337006 -266.591288)
		(end 278.278844 -266.591288)
		(width 0.18288)
		(layer "In11.Cu")
		(net "M_D_CPU0_ALERT_N")
	)
	(segment
		(start 282.44165 -267.275056)
		(end 281.020774 -267.275056)
		(width 0.18288)
		(layer "In11.Cu")
		(net "M_D_CPU0_ALERT_N")
	)
	(arc
		(start 349.11284 -256.77114)
		(mid 348.944284 -256.942734)
		(end 348.882716 -257.175254)
		(width 0.088646)
		(layer "In11.Cu")
		(net "M_D_CPU0_ALERT_N")
	)
	(arc
		(start 348.412562 -259.616956)
		(mid 348.350999 -259.849479)
		(end 348.182438 -260.02107)
		(width 0.088646)
		(layer "In11.Cu")
		(net "M_D_CPU0_ALERT_N")
	)
	(arc
		(start 347.660214 -260.106414)
		(mid 347.473016 -260.056271)
		(end 347.285818 -260.106414)
		(width 0.088646)
		(layer "In11.Cu")
		(net "M_D_CPU0_ALERT_N")
	)
	(arc
		(start 336.430112 -260.023864)
		(mid 336.195162 -259.960904)
		(end 335.960212 -260.023864)
		(width 0.18288)
		(layer "In11.Cu")
		(net "M_D_CPU0_ALERT_N")
	)
	(arc
		(start 348.882716 -257.184906)
		(mid 348.947959 -257.414318)
		(end 349.117412 -257.582162)
		(width 0.088646)
		(layer "In11.Cu")
		(net "M_D_CPU0_ALERT_N")
	)
	(arc
		(start 337.839812 -260.023864)
		(mid 337.604862 -260.086824)
		(end 337.369912 -260.023864)
		(width 0.18288)
		(layer "In11.Cu")
		(net "M_D_CPU0_ALERT_N")
	)
	(arc
		(start 337.35645 -260.01599)
		(mid 337.127197 -259.960746)
		(end 336.900012 -260.023864)
		(width 0.18288)
		(layer "In11.Cu")
		(net "M_D_CPU0_ALERT_N")
	)
	(arc
		(start 339.70976 -260.029452)
		(mid 339.479029 -260.086813)
		(end 339.249766 -260.023864)
		(width 0.18288)
		(layer "In11.Cu")
		(net "M_D_CPU0_ALERT_N")
	)
	(arc
		(start 341.11565 -260.01599)
		(mid 340.886397 -259.960746)
		(end 340.659212 -260.023864)
		(width 0.18288)
		(layer "In11.Cu")
		(net "M_D_CPU0_ALERT_N")
	)
	(arc
		(start 349.352616 -256.361438)
		(mid 349.291053 -256.593961)
		(end 349.122492 -256.765552)
		(width 0.088646)
		(layer "In11.Cu")
		(net "M_D_CPU0_ALERT_N")
	)
	(arc
		(start 350.057212 -255.14046)
		(mid 349.889557 -255.305122)
		(end 349.822516 -255.53035)
		(width 0.088646)
		(layer "In11.Cu")
		(net "M_D_CPU0_ALERT_N")
	)
	(arc
		(start 342.538812 -260.023864)
		(mid 342.303862 -260.086824)
		(end 342.068912 -260.023864)
		(width 0.18288)
		(layer "In11.Cu")
		(net "M_D_CPU0_ALERT_N")
	)
	(arc
		(start 350.154494 -255.065784)
		(mid 350.108294 -255.106301)
		(end 350.057212 -255.14046)
		(width 0.088646)
		(layer "In11.Cu")
		(net "M_D_CPU0_ALERT_N")
	)
	(arc
		(start 344.985848 -260.050026)
		(mid 344.935357 -260.04337)
		(end 344.888312 -260.023864)
		(width 0.18288)
		(layer "In11.Cu")
		(net "M_D_CPU0_ALERT_N")
	)
	(arc
		(start 346.33535 -260.11251)
		(mid 346.057172 -260.182233)
		(end 345.780614 -260.106414)
		(width 0.088646)
		(layer "In11.Cu")
		(net "M_D_CPU0_ALERT_N")
	)
	(arc
		(start 340.189312 -260.023864)
		(mid 339.954362 -259.960904)
		(end 339.719412 -260.023864)
		(width 0.18288)
		(layer "In11.Cu")
		(net "M_D_CPU0_ALERT_N")
	)
	(arc
		(start 340.659212 -260.023864)
		(mid 340.424262 -260.086824)
		(end 340.189312 -260.023864)
		(width 0.18288)
		(layer "In11.Cu")
		(net "M_D_CPU0_ALERT_N")
	)
	(arc
		(start 343.478612 -260.023864)
		(mid 343.243662 -260.086824)
		(end 343.008712 -260.023864)
		(width 0.18288)
		(layer "In11.Cu")
		(net "M_D_CPU0_ALERT_N")
	)
	(arc
		(start 348.642686 -259.212842)
		(mid 348.47413 -259.384436)
		(end 348.412562 -259.616956)
		(width 0.088646)
		(layer "In11.Cu")
		(net "M_D_CPU0_ALERT_N")
	)
	(arc
		(start 336.900012 -260.023864)
		(mid 336.665062 -260.086824)
		(end 336.430112 -260.023864)
		(width 0.18288)
		(layer "In11.Cu")
		(net "M_D_CPU0_ALERT_N")
	)
	(arc
		(start 342.05545 -260.01599)
		(mid 341.826197 -259.960746)
		(end 341.599012 -260.023864)
		(width 0.18288)
		(layer "In11.Cu")
		(net "M_D_CPU0_ALERT_N")
	)
	(arc
		(start 349.822516 -255.547622)
		(mid 349.762561 -255.777232)
		(end 349.59798 -255.94818)
		(width 0.088646)
		(layer "In11.Cu")
		(net "M_D_CPU0_ALERT_N")
	)
	(arc
		(start 344.888312 -260.023864)
		(mid 344.661125 -259.960846)
		(end 344.431874 -260.01599)
		(width 0.18288)
		(layer "In11.Cu")
		(net "M_D_CPU0_ALERT_N")
	)
	(arc
		(start 343.008712 -260.023864)
		(mid 342.781525 -259.960846)
		(end 342.552274 -260.01599)
		(width 0.18288)
		(layer "In11.Cu")
		(net "M_D_CPU0_ALERT_N")
	)
	(arc
		(start 346.72016 -260.106414)
		(mid 346.532962 -260.056271)
		(end 346.345764 -260.106414)
		(width 0.088646)
		(layer "In11.Cu")
		(net "M_D_CPU0_ALERT_N")
	)
	(arc
		(start 335.020412 -260.023864)
		(mid 334.785462 -260.086824)
		(end 334.550512 -260.023864)
		(width 0.18288)
		(layer "In11.Cu")
		(net "M_D_CPU0_ALERT_N")
	)
	(arc
		(start 343.93505 -260.01599)
		(mid 343.705797 -259.960746)
		(end 343.478612 -260.023864)
		(width 0.18288)
		(layer "In11.Cu")
		(net "M_D_CPU0_ALERT_N")
	)
	(arc
		(start 348.882716 -258.80314)
		(mid 348.822761 -259.03275)
		(end 348.65818 -259.203698)
		(width 0.088646)
		(layer "In11.Cu")
		(net "M_D_CPU0_ALERT_N")
	)
	(arc
		(start 349.117412 -258.396232)
		(mid 348.949108 -258.561972)
		(end 348.882716 -258.788662)
		(width 0.088646)
		(layer "In11.Cu")
		(net "M_D_CPU0_ALERT_N")
	)
	(arc
		(start 348.034864 -260.10616)
		(mid 347.847585 -260.15643)
		(end 347.660214 -260.106414)
		(width 0.088646)
		(layer "In11.Cu")
		(net "M_D_CPU0_ALERT_N")
	)
	(arc
		(start 345.780614 -260.106414)
		(mid 345.679168 -260.06439)
		(end 345.570302 -260.050026)
		(width 0.088646)
		(layer "In11.Cu")
		(net "M_D_CPU0_ALERT_N")
	)
	(arc
		(start 349.352362 -258.002532)
		(mid 349.286139 -258.229969)
		(end 349.117412 -258.396232)
		(width 0.088646)
		(layer "In11.Cu")
		(net "M_D_CPU0_ALERT_N")
	)
	(arc
		(start 347.285818 -260.106414)
		(mid 347.009005 -260.182284)
		(end 346.730574 -260.11251)
		(width 0.088646)
		(layer "In11.Cu")
		(net "M_D_CPU0_ALERT_N")
	)
	(arc
		(start 335.490312 -260.023864)
		(mid 335.255362 -259.960904)
		(end 335.020412 -260.023864)
		(width 0.18288)
		(layer "In11.Cu")
		(net "M_D_CPU0_ALERT_N")
	)
	(arc
		(start 334.550512 -260.023864)
		(mid 334.315562 -259.960904)
		(end 334.080612 -260.023864)
		(width 0.18288)
		(layer "In11.Cu")
		(net "M_D_CPU0_ALERT_N")
	)
	(arc
		(start 339.240114 -260.018276)
		(mid 339.009129 -259.960793)
		(end 338.779612 -260.023864)
		(width 0.18288)
		(layer "In11.Cu")
		(net "M_D_CPU0_ALERT_N")
	)
	(arc
		(start 349.122238 -257.584956)
		(mid 349.290794 -257.75655)
		(end 349.352362 -257.98907)
		(width 0.088646)
		(layer "In11.Cu")
		(net "M_D_CPU0_ALERT_N")
	)
	(arc
		(start 349.587312 -255.95453)
		(mid 349.419008 -256.12027)
		(end 349.352616 -256.34696)
		(width 0.088646)
		(layer "In11.Cu")
		(net "M_D_CPU0_ALERT_N")
	)
	(arc
		(start 338.29625 -260.01599)
		(mid 338.066997 -259.960746)
		(end 337.839812 -260.023864)
		(width 0.18288)
		(layer "In11.Cu")
		(net "M_D_CPU0_ALERT_N")
	)
	(arc
		(start 335.960212 -260.023864)
		(mid 335.725262 -260.086824)
		(end 335.490312 -260.023864)
		(width 0.18288)
		(layer "In11.Cu")
		(net "M_D_CPU0_ALERT_N")
	)
	(arc
		(start 334.080612 -260.023864)
		(mid 333.845662 -260.086824)
		(end 333.610712 -260.023864)
		(width 0.18288)
		(layer "In11.Cu")
		(net "M_D_CPU0_ALERT_N")
	)
	(arc
		(start 344.418412 -260.023864)
		(mid 344.183462 -260.086824)
		(end 343.948512 -260.023864)
		(width 0.18288)
		(layer "In11.Cu")
		(net "M_D_CPU0_ALERT_N")
	)
	(arc
		(start 338.779612 -260.023864)
		(mid 338.544662 -260.086824)
		(end 338.309712 -260.023864)
		(width 0.18288)
		(layer "In11.Cu")
		(net "M_D_CPU0_ALERT_N")
	)
	(arc
		(start 341.599012 -260.023864)
		(mid 341.364062 -260.086824)
		(end 341.129112 -260.023864)
		(width 0.18288)
		(layer "In11.Cu")
		(net "M_D_CPU0_ALERT_N")
	)
	(segment
		(start 30.771846 -243.216684)
		(end 31.876746 -243.216684)
		(width 0.20066)
		(layer "F.Cu")
		(net "M_C_CPU1_SB_RSP<1>")
	)
	(segment
		(start 96.713294 -253.383796)
		(end 96.713294 -253.919482)
		(width 0.20066)
		(layer "F.Cu")
		(net "M_C_CPU1_SB_RSP<1>")
	)
	(segment
		(start 96.713294 -253.919482)
		(end 96.713548 -253.919736)
		(width 0.20066)
		(layer "F.Cu")
		(net "M_C_CPU1_SB_RSP<1>")
	)
	(segment
		(start 35.294062 -244.490748)
		(end 35.134042 -244.330728)
		(width 0.18288)
		(layer "In6.Cu")
		(net "M_C_CPU1_SB_RSP<1>")
	)
	(segment
		(start 38.52418 -244.85473)
		(end 38.160198 -244.490748)
		(width 0.18288)
		(layer "In6.Cu")
		(net "M_C_CPU1_SB_RSP<1>")
	)
	(segment
		(start 44.586144 -247.815354)
		(end 43.596306 -248.113296)
		(width 0.18288)
		(layer "In6.Cu")
		(net "M_C_CPU1_SB_RSP<1>")
	)
	(segment
		(start 41.755822 -248.113296)
		(end 40.99052 -248.113296)
		(width 0.18288)
		(layer "In6.Cu")
		(net "M_C_CPU1_SB_RSP<1>")
	)
	(segment
		(start 63.563754 -251.422154)
		(end 62.8142 -252.171708)
		(width 0.18288)
		(layer "In6.Cu")
		(net "M_C_CPU1_SB_RSP<1>")
	)
	(segment
		(start 34.391092 -244.4623)
		(end 34.231072 -244.62232)
		(width 0.18288)
		(layer "In6.Cu")
		(net "M_C_CPU1_SB_RSP<1>")
	)
	(segment
		(start 35.134042 -244.330728)
		(end 35.134042 -243.774976)
		(width 0.18288)
		(layer "In6.Cu")
		(net "M_C_CPU1_SB_RSP<1>")
	)
	(segment
		(start 65.091564 -252.018038)
		(end 64.49568 -251.422154)
		(width 0.18288)
		(layer "In6.Cu")
		(net "M_C_CPU1_SB_RSP<1>")
	)
	(segment
		(start 34.231072 -244.62232)
		(end 33.282382 -244.62232)
		(width 0.18288)
		(layer "In6.Cu")
		(net "M_C_CPU1_SB_RSP<1>")
	)
	(segment
		(start 56.938926 -251.370846)
		(end 56.105806 -251.370846)
		(width 0.18288)
		(layer "In6.Cu")
		(net "M_C_CPU1_SB_RSP<1>")
	)
	(segment
		(start 84.434934 -252.88367)
		(end 81.691734 -252.88367)
		(width 0.18288)
		(layer "In6.Cu")
		(net "M_C_CPU1_SB_RSP<1>")
	)
	(segment
		(start 38.52418 -246.89308)
		(end 38.52418 -244.85473)
		(width 0.18288)
		(layer "In6.Cu")
		(net "M_C_CPU1_SB_RSP<1>")
	)
	(segment
		(start 54.927246 -251.190506)
		(end 51.533806 -250.441206)
		(width 0.18288)
		(layer "In6.Cu")
		(net "M_C_CPU1_SB_RSP<1>")
	)
	(segment
		(start 42.121582 -247.161304)
		(end 41.938702 -247.344184)
		(width 0.18288)
		(layer "In6.Cu")
		(net "M_C_CPU1_SB_RSP<1>")
	)
	(segment
		(start 75.454256 -253.60122)
		(end 68.913756 -253.60122)
		(width 0.18288)
		(layer "In6.Cu")
		(net "M_C_CPU1_SB_RSP<1>")
	)
	(segment
		(start 76.973938 -254.230632)
		(end 76.653136 -254.09779)
		(width 0.18288)
		(layer "In6.Cu")
		(net "M_C_CPU1_SB_RSP<1>")
	)
	(segment
		(start 43.596306 -248.113296)
		(end 42.812462 -248.113296)
		(width 0.18288)
		(layer "In6.Cu")
		(net "M_C_CPU1_SB_RSP<1>")
	)
	(segment
		(start 50.935636 -250.441206)
		(end 50.541936 -250.204986)
		(width 0.18288)
		(layer "In6.Cu")
		(net "M_C_CPU1_SB_RSP<1>")
	)
	(segment
		(start 90.332306 -254.237998)
		(end 90.321892 -254.244094)
		(width 0.088646)
		(layer "In6.Cu")
		(net "M_C_CPU1_SB_RSP<1>")
	)
	(segment
		(start 96.062292 -253.433834)
		(end 96.056196 -253.430278)
		(width 0.088646)
		(layer "In6.Cu")
		(net "M_C_CPU1_SB_RSP<1>")
	)
	(segment
		(start 76.653136 -254.09779)
		(end 76.647294 -254.095504)
		(width 0.18288)
		(layer "In6.Cu")
		(net "M_C_CPU1_SB_RSP<1>")
	)
	(segment
		(start 42.629582 -247.344184)
		(end 42.446702 -247.161304)
		(width 0.18288)
		(layer "In6.Cu")
		(net "M_C_CPU1_SB_RSP<1>")
	)
	(segment
		(start 40.99052 -248.113296)
		(end 40.075104 -247.19788)
		(width 0.18288)
		(layer "In6.Cu")
		(net "M_C_CPU1_SB_RSP<1>")
	)
	(segment
		(start 96.056196 -253.430278)
		(end 96.041464 -253.421642)
		(width 0.088646)
		(layer "In6.Cu")
		(net "M_C_CPU1_SB_RSP<1>")
	)
	(segment
		(start 92.216478 -254.235458)
		(end 92.201746 -254.244094)
		(width 0.088646)
		(layer "In6.Cu")
		(net "M_C_CPU1_SB_RSP<1>")
	)
	(segment
		(start 41.938702 -247.344184)
		(end 41.938702 -247.930416)
		(width 0.18288)
		(layer "In6.Cu")
		(net "M_C_CPU1_SB_RSP<1>")
	)
	(segment
		(start 86.110318 -254.184912)
		(end 84.809076 -252.88367)
		(width 0.088646)
		(layer "In6.Cu")
		(net "M_C_CPU1_SB_RSP<1>")
	)
	(segment
		(start 42.446702 -247.161304)
		(end 42.121582 -247.161304)
		(width 0.18288)
		(layer "In6.Cu")
		(net "M_C_CPU1_SB_RSP<1>")
	)
	(segment
		(start 46.377606 -247.891046)
		(end 44.586144 -247.815354)
		(width 0.18288)
		(layer "In6.Cu")
		(net "M_C_CPU1_SB_RSP<1>")
	)
	(segment
		(start 47.191168 -247.891046)
		(end 46.377606 -247.891046)
		(width 0.18288)
		(layer "In6.Cu")
		(net "M_C_CPU1_SB_RSP<1>")
	)
	(segment
		(start 51.533806 -250.441206)
		(end 50.935636 -250.441206)
		(width 0.18288)
		(layer "In6.Cu")
		(net "M_C_CPU1_SB_RSP<1>")
	)
	(segment
		(start 84.809076 -252.88367)
		(end 84.434934 -252.88367)
		(width 0.088646)
		(layer "In6.Cu")
		(net "M_C_CPU1_SB_RSP<1>")
	)
	(segment
		(start 62.8142 -252.171708)
		(end 57.739788 -252.171708)
		(width 0.18288)
		(layer "In6.Cu")
		(net "M_C_CPU1_SB_RSP<1>")
	)
	(segment
		(start 49.267872 -248.819162)
		(end 47.191168 -247.891046)
		(width 0.18288)
		(layer "In6.Cu")
		(net "M_C_CPU1_SB_RSP<1>")
	)
	(segment
		(start 96.713548 -253.919736)
		(end 96.40062 -253.919736)
		(width 0.088646)
		(layer "In6.Cu")
		(net "M_C_CPU1_SB_RSP<1>")
	)
	(segment
		(start 33.282382 -244.62232)
		(end 31.876746 -243.216684)
		(width 0.18288)
		(layer "In6.Cu")
		(net "M_C_CPU1_SB_RSP<1>")
	)
	(segment
		(start 41.938702 -247.930416)
		(end 41.755822 -248.113296)
		(width 0.18288)
		(layer "In6.Cu")
		(net "M_C_CPU1_SB_RSP<1>")
	)
	(segment
		(start 42.812462 -248.113296)
		(end 42.629582 -247.930416)
		(width 0.18288)
		(layer "In6.Cu")
		(net "M_C_CPU1_SB_RSP<1>")
	)
	(segment
		(start 78.439518 -254.230632)
		(end 76.973938 -254.230632)
		(width 0.18288)
		(layer "In6.Cu")
		(net "M_C_CPU1_SB_RSP<1>")
	)
	(segment
		(start 38.160198 -244.490748)
		(end 35.294062 -244.490748)
		(width 0.18288)
		(layer "In6.Cu")
		(net "M_C_CPU1_SB_RSP<1>")
	)
	(segment
		(start 81.691734 -252.88367)
		(end 78.439518 -254.230632)
		(width 0.18288)
		(layer "In6.Cu")
		(net "M_C_CPU1_SB_RSP<1>")
	)
	(segment
		(start 35.134042 -243.774976)
		(end 34.951162 -243.592096)
		(width 0.18288)
		(layer "In6.Cu")
		(net "M_C_CPU1_SB_RSP<1>")
	)
	(segment
		(start 57.739788 -252.171708)
		(end 56.938926 -251.370846)
		(width 0.18288)
		(layer "In6.Cu")
		(net "M_C_CPU1_SB_RSP<1>")
	)
	(segment
		(start 50.541936 -250.204986)
		(end 49.267872 -248.819162)
		(width 0.18288)
		(layer "In6.Cu")
		(net "M_C_CPU1_SB_RSP<1>")
	)
	(segment
		(start 68.913756 -253.60122)
		(end 65.091564 -252.018038)
		(width 0.18288)
		(layer "In6.Cu")
		(net "M_C_CPU1_SB_RSP<1>")
	)
	(segment
		(start 34.951162 -243.592096)
		(end 34.551112 -243.592096)
		(width 0.18288)
		(layer "In6.Cu")
		(net "M_C_CPU1_SB_RSP<1>")
	)
	(segment
		(start 42.629582 -247.930416)
		(end 42.629582 -247.344184)
		(width 0.18288)
		(layer "In6.Cu")
		(net "M_C_CPU1_SB_RSP<1>")
	)
	(segment
		(start 76.647294 -254.095504)
		(end 75.454256 -253.60122)
		(width 0.18288)
		(layer "In6.Cu")
		(net "M_C_CPU1_SB_RSP<1>")
	)
	(segment
		(start 34.391092 -243.752116)
		(end 34.391092 -244.4623)
		(width 0.18288)
		(layer "In6.Cu")
		(net "M_C_CPU1_SB_RSP<1>")
	)
	(segment
		(start 34.551112 -243.592096)
		(end 34.391092 -243.752116)
		(width 0.18288)
		(layer "In6.Cu")
		(net "M_C_CPU1_SB_RSP<1>")
	)
	(segment
		(start 40.075104 -247.19788)
		(end 38.82898 -247.19788)
		(width 0.18288)
		(layer "In6.Cu")
		(net "M_C_CPU1_SB_RSP<1>")
	)
	(segment
		(start 55.976774 -251.351034)
		(end 54.927246 -251.190506)
		(width 0.18288)
		(layer "In6.Cu")
		(net "M_C_CPU1_SB_RSP<1>")
	)
	(segment
		(start 95.124524 -253.435104)
		(end 95.116142 -253.430278)
		(width 0.088646)
		(layer "In6.Cu")
		(net "M_C_CPU1_SB_RSP<1>")
	)
	(segment
		(start 56.105806 -251.370846)
		(end 55.976774 -251.351034)
		(width 0.18288)
		(layer "In6.Cu")
		(net "M_C_CPU1_SB_RSP<1>")
	)
	(segment
		(start 64.49568 -251.422154)
		(end 63.563754 -251.422154)
		(width 0.18288)
		(layer "In6.Cu")
		(net "M_C_CPU1_SB_RSP<1>")
	)
	(segment
		(start 38.82898 -247.19788)
		(end 38.52418 -246.89308)
		(width 0.18288)
		(layer "In6.Cu")
		(net "M_C_CPU1_SB_RSP<1>")
	)
	(segment
		(start 95.116142 -253.430278)
		(end 95.10141 -253.421642)
		(width 0.088646)
		(layer "In6.Cu")
		(net "M_C_CPU1_SB_RSP<1>")
	)
	(segment
		(start 93.156278 -254.235458)
		(end 93.141546 -254.244094)
		(width 0.088646)
		(layer "In6.Cu")
		(net "M_C_CPU1_SB_RSP<1>")
	)
	(segment
		(start 94.268544 -253.904242)
		(end 94.268544 -253.928372)
		(width 0.088646)
		(layer "In6.Cu")
		(net "M_C_CPU1_SB_RSP<1>")
	)
	(segment
		(start 96.40062 -253.919736)
		(end 96.335088 -253.854204)
		(width 0.088646)
		(layer "In6.Cu")
		(net "M_C_CPU1_SB_RSP<1>")
	)
	(arc
		(start 96.041464 -253.421642)
		(mid 95.764989 -253.354322)
		(end 95.490792 -253.430278)
		(width 0.088646)
		(layer "In6.Cu")
		(net "M_C_CPU1_SB_RSP<1>")
	)
	(arc
		(start 90.88755 -254.244094)
		(mid 90.610737 -254.168224)
		(end 90.332306 -254.237998)
		(width 0.088646)
		(layer "In6.Cu")
		(net "M_C_CPU1_SB_RSP<1>")
	)
	(arc
		(start 96.335088 -253.854204)
		(mid 96.247844 -253.612116)
		(end 96.062292 -253.433834)
		(width 0.088646)
		(layer "In6.Cu")
		(net "M_C_CPU1_SB_RSP<1>")
	)
	(arc
		(start 93.141546 -254.244094)
		(mid 92.954348 -254.294237)
		(end 92.76715 -254.244094)
		(width 0.088646)
		(layer "In6.Cu")
		(net "M_C_CPU1_SB_RSP<1>")
	)
	(arc
		(start 87.502492 -254.244094)
		(mid 87.315294 -254.294237)
		(end 87.128096 -254.244094)
		(width 0.088646)
		(layer "In6.Cu")
		(net "M_C_CPU1_SB_RSP<1>")
	)
	(arc
		(start 86.562692 -254.244094)
		(mid 86.375494 -254.294237)
		(end 86.188296 -254.244094)
		(width 0.088646)
		(layer "In6.Cu")
		(net "M_C_CPU1_SB_RSP<1>")
	)
	(arc
		(start 86.188296 -254.244094)
		(mid 86.147366 -254.217061)
		(end 86.110318 -254.184912)
		(width 0.088646)
		(layer "In6.Cu")
		(net "M_C_CPU1_SB_RSP<1>")
	)
	(arc
		(start 87.128096 -254.244094)
		(mid 86.845394 -254.168318)
		(end 86.562692 -254.244094)
		(width 0.088646)
		(layer "In6.Cu")
		(net "M_C_CPU1_SB_RSP<1>")
	)
	(arc
		(start 92.76715 -254.244094)
		(mid 92.492951 -254.168259)
		(end 92.216478 -254.235458)
		(width 0.088646)
		(layer "In6.Cu")
		(net "M_C_CPU1_SB_RSP<1>")
	)
	(arc
		(start 91.82735 -254.244094)
		(mid 91.544648 -254.168318)
		(end 91.261946 -254.244094)
		(width 0.088646)
		(layer "In6.Cu")
		(net "M_C_CPU1_SB_RSP<1>")
	)
	(arc
		(start 95.10141 -253.421642)
		(mid 94.824935 -253.354322)
		(end 94.550738 -253.430278)
		(width 0.088646)
		(layer "In6.Cu")
		(net "M_C_CPU1_SB_RSP<1>")
	)
	(arc
		(start 89.947496 -254.244094)
		(mid 89.664794 -254.168318)
		(end 89.382092 -254.244094)
		(width 0.088646)
		(layer "In6.Cu")
		(net "M_C_CPU1_SB_RSP<1>")
	)
	(arc
		(start 94.081346 -254.244094)
		(mid 93.894148 -254.294237)
		(end 93.70695 -254.244094)
		(width 0.088646)
		(layer "In6.Cu")
		(net "M_C_CPU1_SB_RSP<1>")
	)
	(arc
		(start 94.268544 -253.928372)
		(mid 94.216274 -254.110737)
		(end 94.081346 -254.244094)
		(width 0.088646)
		(layer "In6.Cu")
		(net "M_C_CPU1_SB_RSP<1>")
	)
	(arc
		(start 91.261946 -254.244094)
		(mid 91.074748 -254.294237)
		(end 90.88755 -254.244094)
		(width 0.088646)
		(layer "In6.Cu")
		(net "M_C_CPU1_SB_RSP<1>")
	)
	(arc
		(start 89.007696 -254.244094)
		(mid 88.724994 -254.168318)
		(end 88.442292 -254.244094)
		(width 0.088646)
		(layer "In6.Cu")
		(net "M_C_CPU1_SB_RSP<1>")
	)
	(arc
		(start 90.321892 -254.244094)
		(mid 90.134694 -254.294237)
		(end 89.947496 -254.244094)
		(width 0.088646)
		(layer "In6.Cu")
		(net "M_C_CPU1_SB_RSP<1>")
	)
	(arc
		(start 93.70695 -254.244094)
		(mid 93.432751 -254.168259)
		(end 93.156278 -254.235458)
		(width 0.088646)
		(layer "In6.Cu")
		(net "M_C_CPU1_SB_RSP<1>")
	)
	(arc
		(start 88.442292 -254.244094)
		(mid 88.255094 -254.294237)
		(end 88.067896 -254.244094)
		(width 0.088646)
		(layer "In6.Cu")
		(net "M_C_CPU1_SB_RSP<1>")
	)
	(arc
		(start 94.550738 -253.430278)
		(mid 94.347915 -253.630509)
		(end 94.268544 -253.904242)
		(width 0.088646)
		(layer "In6.Cu")
		(net "M_C_CPU1_SB_RSP<1>")
	)
	(arc
		(start 89.382092 -254.244094)
		(mid 89.194894 -254.294237)
		(end 89.007696 -254.244094)
		(width 0.088646)
		(layer "In6.Cu")
		(net "M_C_CPU1_SB_RSP<1>")
	)
	(arc
		(start 92.201746 -254.244094)
		(mid 92.014548 -254.294237)
		(end 91.82735 -254.244094)
		(width 0.088646)
		(layer "In6.Cu")
		(net "M_C_CPU1_SB_RSP<1>")
	)
	(arc
		(start 95.490792 -253.430278)
		(mid 95.308287 -253.480516)
		(end 95.124524 -253.435104)
		(width 0.088646)
		(layer "In6.Cu")
		(net "M_C_CPU1_SB_RSP<1>")
	)
	(arc
		(start 88.067896 -254.244094)
		(mid 87.785194 -254.168318)
		(end 87.502492 -254.244094)
		(width 0.088646)
		(layer "In6.Cu")
		(net "M_C_CPU1_SB_RSP<1>")
	)
	(segment
		(start 23.228046 -243.216684)
		(end 24.332946 -243.216684)
		(width 0.20066)
		(layer "F.Cu")
		(net "M_C_CPU1_SB_RSP<0>")
	)
	(segment
		(start 97.183448 -254.733298)
		(end 97.183194 -254.733552)
		(width 0.20066)
		(layer "F.Cu")
		(net "M_C_CPU1_SB_RSP<0>")
	)
	(segment
		(start 97.183448 -254.197612)
		(end 97.183448 -254.733298)
		(width 0.20066)
		(layer "F.Cu")
		(net "M_C_CPU1_SB_RSP<0>")
	)
	(segment
		(start 75.531218 -254.75692)
		(end 75.307698 -254.664464)
		(width 0.18288)
		(layer "In6.Cu")
		(net "M_C_CPU1_SB_RSP<0>")
	)
	(segment
		(start 75.916536 -254.916686)
		(end 75.531218 -254.75692)
		(width 0.18288)
		(layer "In6.Cu")
		(net "M_C_CPU1_SB_RSP<0>")
	)
	(segment
		(start 91.35745 -255.05791)
		(end 91.347036 -255.051814)
		(width 0.088646)
		(layer "In6.Cu")
		(net "M_C_CPU1_SB_RSP<0>")
	)
	(segment
		(start 47.446692 -249.77725)
		(end 47.140368 -249.591068)
		(width 0.18288)
		(layer "In6.Cu")
		(net "M_C_CPU1_SB_RSP<0>")
	)
	(segment
		(start 32.398208 -246.413528)
		(end 32.103822 -246.19077)
		(width 0.18288)
		(layer "In6.Cu")
		(net "M_C_CPU1_SB_RSP<0>")
	)
	(segment
		(start 94.176596 -255.05791)
		(end 94.161864 -255.049274)
		(width 0.088646)
		(layer "In6.Cu")
		(net "M_C_CPU1_SB_RSP<0>")
	)
	(segment
		(start 95.975678 -254.235458)
		(end 95.960946 -254.244094)
		(width 0.088646)
		(layer "In6.Cu")
		(net "M_C_CPU1_SB_RSP<0>")
	)
	(segment
		(start 46.542706 -249.591068)
		(end 44.983146 -249.51563)
		(width 0.18288)
		(layer "In6.Cu")
		(net "M_C_CPU1_SB_RSP<0>")
	)
	(segment
		(start 94.551246 -255.057656)
		(end 94.550992 -255.05791)
		(width 0.088646)
		(layer "In6.Cu")
		(net "M_C_CPU1_SB_RSP<0>")
	)
	(segment
		(start 84.836508 -254.194818)
		(end 84.836508 -254.130048)
		(width 0.088646)
		(layer "In6.Cu")
		(net "M_C_CPU1_SB_RSP<0>")
	)
	(segment
		(start 47.140368 -249.591068)
		(end 46.542706 -249.591068)
		(width 0.18288)
		(layer "In6.Cu")
		(net "M_C_CPU1_SB_RSP<0>")
	)
	(segment
		(start 84.593684 -253.887224)
		(end 84.434934 -253.887224)
		(width 0.088646)
		(layer "In6.Cu")
		(net "M_C_CPU1_SB_RSP<0>")
	)
	(segment
		(start 43.085766 -249.844814)
		(end 41.599866 -249.844814)
		(width 0.18288)
		(layer "In6.Cu")
		(net "M_C_CPU1_SB_RSP<0>")
	)
	(segment
		(start 85.640418 -254.998728)
		(end 84.836508 -254.194818)
		(width 0.088646)
		(layer "In6.Cu")
		(net "M_C_CPU1_SB_RSP<0>")
	)
	(segment
		(start 89.477596 -255.05791)
		(end 89.462864 -255.049274)
		(width 0.088646)
		(layer "In6.Cu")
		(net "M_C_CPU1_SB_RSP<0>")
	)
	(segment
		(start 65.312798 -253.20498)
		(end 50.997104 -253.20498)
		(width 0.18288)
		(layer "In6.Cu")
		(net "M_C_CPU1_SB_RSP<0>")
	)
	(segment
		(start 78.670404 -254.916686)
		(end 75.916536 -254.916686)
		(width 0.18288)
		(layer "In6.Cu")
		(net "M_C_CPU1_SB_RSP<0>")
	)
	(segment
		(start 71.129144 -254.66421)
		(end 68.836032 -254.66421)
		(width 0.18288)
		(layer "In6.Cu")
		(net "M_C_CPU1_SB_RSP<0>")
	)
	(segment
		(start 84.434934 -253.887224)
		(end 81.156048 -253.887224)
		(width 0.18288)
		(layer "In6.Cu")
		(net "M_C_CPU1_SB_RSP<0>")
	)
	(segment
		(start 50.997104 -253.20498)
		(end 48.613568 -251.458476)
		(width 0.18288)
		(layer "In6.Cu")
		(net "M_C_CPU1_SB_RSP<0>")
	)
	(segment
		(start 44.983146 -249.51563)
		(end 44.680886 -249.51563)
		(width 0.18288)
		(layer "In6.Cu")
		(net "M_C_CPU1_SB_RSP<0>")
	)
	(segment
		(start 33.188148 -247.643904)
		(end 32.398208 -246.413528)
		(width 0.18288)
		(layer "In6.Cu")
		(net "M_C_CPU1_SB_RSP<0>")
	)
	(segment
		(start 71.129398 -254.664464)
		(end 71.129144 -254.66421)
		(width 0.18288)
		(layer "In6.Cu")
		(net "M_C_CPU1_SB_RSP<0>")
	)
	(segment
		(start 75.307698 -254.664464)
		(end 71.129398 -254.664464)
		(width 0.18288)
		(layer "In6.Cu")
		(net "M_C_CPU1_SB_RSP<0>")
	)
	(segment
		(start 32.103822 -246.19077)
		(end 27.307032 -246.19077)
		(width 0.18288)
		(layer "In6.Cu")
		(net "M_C_CPU1_SB_RSP<0>")
	)
	(segment
		(start 93.236796 -255.05791)
		(end 93.222064 -255.049274)
		(width 0.088646)
		(layer "In6.Cu")
		(net "M_C_CPU1_SB_RSP<0>")
	)
	(segment
		(start 41.599866 -249.844814)
		(end 37.843206 -248.288556)
		(width 0.18288)
		(layer "In6.Cu")
		(net "M_C_CPU1_SB_RSP<0>")
	)
	(segment
		(start 84.836508 -254.130048)
		(end 84.593684 -253.887224)
		(width 0.088646)
		(layer "In6.Cu")
		(net "M_C_CPU1_SB_RSP<0>")
	)
	(segment
		(start 37.843206 -248.288556)
		(end 37.445442 -247.890792)
		(width 0.18288)
		(layer "In6.Cu")
		(net "M_C_CPU1_SB_RSP<0>")
	)
	(segment
		(start 27.307032 -246.19077)
		(end 24.332946 -243.216684)
		(width 0.18288)
		(layer "In6.Cu")
		(net "M_C_CPU1_SB_RSP<0>")
	)
	(segment
		(start 91.74226 -255.051814)
		(end 91.731846 -255.05791)
		(width 0.088646)
		(layer "In6.Cu")
		(net "M_C_CPU1_SB_RSP<0>")
	)
	(segment
		(start 48.613568 -251.458476)
		(end 47.446692 -249.77725)
		(width 0.18288)
		(layer "In6.Cu")
		(net "M_C_CPU1_SB_RSP<0>")
	)
	(segment
		(start 81.156048 -253.887224)
		(end 78.670404 -254.916686)
		(width 0.18288)
		(layer "In6.Cu")
		(net "M_C_CPU1_SB_RSP<0>")
	)
	(segment
		(start 44.680886 -249.51563)
		(end 43.085766 -249.844814)
		(width 0.18288)
		(layer "In6.Cu")
		(net "M_C_CPU1_SB_RSP<0>")
	)
	(segment
		(start 37.445442 -247.890792)
		(end 33.435036 -247.890792)
		(width 0.18288)
		(layer "In6.Cu")
		(net "M_C_CPU1_SB_RSP<0>")
	)
	(segment
		(start 33.435036 -247.890792)
		(end 33.188148 -247.643904)
		(width 0.18288)
		(layer "In6.Cu")
		(net "M_C_CPU1_SB_RSP<0>")
	)
	(segment
		(start 68.836032 -254.66421)
		(end 65.312798 -253.20498)
		(width 0.18288)
		(layer "In6.Cu")
		(net "M_C_CPU1_SB_RSP<0>")
	)
	(segment
		(start 95.021146 -254.244094)
		(end 95.021146 -254.244348)
		(width 0.088646)
		(layer "In6.Cu")
		(net "M_C_CPU1_SB_RSP<0>")
	)
	(arc
		(start 94.738444 -254.733552)
		(mid 94.68828 -254.92069)
		(end 94.551246 -255.057656)
		(width 0.088646)
		(layer "In6.Cu")
		(net "M_C_CPU1_SB_RSP<0>")
	)
	(arc
		(start 93.222064 -255.049274)
		(mid 92.945623 -254.982108)
		(end 92.671392 -255.05791)
		(width 0.088646)
		(layer "In6.Cu")
		(net "M_C_CPU1_SB_RSP<0>")
	)
	(arc
		(start 88.537796 -255.05791)
		(mid 88.255094 -254.982168)
		(end 87.972392 -255.05791)
		(width 0.088646)
		(layer "In6.Cu")
		(net "M_C_CPU1_SB_RSP<0>")
	)
	(arc
		(start 94.550992 -255.05791)
		(mid 94.363794 -255.108053)
		(end 94.176596 -255.05791)
		(width 0.088646)
		(layer "In6.Cu")
		(net "M_C_CPU1_SB_RSP<0>")
	)
	(arc
		(start 95.021146 -254.244348)
		(mid 94.814291 -254.45109)
		(end 94.738444 -254.733552)
		(width 0.088646)
		(layer "In6.Cu")
		(net "M_C_CPU1_SB_RSP<0>")
	)
	(arc
		(start 89.851992 -255.05791)
		(mid 89.664794 -255.108053)
		(end 89.477596 -255.05791)
		(width 0.088646)
		(layer "In6.Cu")
		(net "M_C_CPU1_SB_RSP<0>")
	)
	(arc
		(start 95.960946 -254.244094)
		(mid 95.773748 -254.294237)
		(end 95.58655 -254.244094)
		(width 0.088646)
		(layer "In6.Cu")
		(net "M_C_CPU1_SB_RSP<0>")
	)
	(arc
		(start 92.671392 -255.05791)
		(mid 92.484194 -255.108053)
		(end 92.296996 -255.05791)
		(width 0.088646)
		(layer "In6.Cu")
		(net "M_C_CPU1_SB_RSP<0>")
	)
	(arc
		(start 87.032592 -255.05791)
		(mid 86.845394 -255.108053)
		(end 86.658196 -255.05791)
		(width 0.088646)
		(layer "In6.Cu")
		(net "M_C_CPU1_SB_RSP<0>")
	)
	(arc
		(start 92.296996 -255.05791)
		(mid 92.020437 -254.982201)
		(end 91.74226 -255.051814)
		(width 0.088646)
		(layer "In6.Cu")
		(net "M_C_CPU1_SB_RSP<0>")
	)
	(arc
		(start 96.52635 -254.244094)
		(mid 96.252151 -254.168259)
		(end 95.975678 -254.235458)
		(width 0.088646)
		(layer "In6.Cu")
		(net "M_C_CPU1_SB_RSP<0>")
	)
	(arc
		(start 90.417396 -255.05791)
		(mid 90.134694 -254.982168)
		(end 89.851992 -255.05791)
		(width 0.088646)
		(layer "In6.Cu")
		(net "M_C_CPU1_SB_RSP<0>")
	)
	(arc
		(start 95.58655 -254.244094)
		(mid 95.303848 -254.168318)
		(end 95.021146 -254.244094)
		(width 0.088646)
		(layer "In6.Cu")
		(net "M_C_CPU1_SB_RSP<0>")
	)
	(arc
		(start 88.912192 -255.05791)
		(mid 88.724994 -255.108053)
		(end 88.537796 -255.05791)
		(width 0.088646)
		(layer "In6.Cu")
		(net "M_C_CPU1_SB_RSP<0>")
	)
	(arc
		(start 91.347036 -255.051814)
		(mid 91.068604 -254.982)
		(end 90.791792 -255.05791)
		(width 0.088646)
		(layer "In6.Cu")
		(net "M_C_CPU1_SB_RSP<0>")
	)
	(arc
		(start 90.791792 -255.05791)
		(mid 90.604594 -255.108053)
		(end 90.417396 -255.05791)
		(width 0.088646)
		(layer "In6.Cu")
		(net "M_C_CPU1_SB_RSP<0>")
	)
	(arc
		(start 91.731846 -255.05791)
		(mid 91.544648 -255.108053)
		(end 91.35745 -255.05791)
		(width 0.088646)
		(layer "In6.Cu")
		(net "M_C_CPU1_SB_RSP<0>")
	)
	(arc
		(start 94.161864 -255.049274)
		(mid 93.885423 -254.982108)
		(end 93.611192 -255.05791)
		(width 0.088646)
		(layer "In6.Cu")
		(net "M_C_CPU1_SB_RSP<0>")
	)
	(arc
		(start 93.611192 -255.05791)
		(mid 93.423994 -255.108053)
		(end 93.236796 -255.05791)
		(width 0.088646)
		(layer "In6.Cu")
		(net "M_C_CPU1_SB_RSP<0>")
	)
	(arc
		(start 87.597996 -255.05791)
		(mid 87.315294 -254.982168)
		(end 87.032592 -255.05791)
		(width 0.088646)
		(layer "In6.Cu")
		(net "M_C_CPU1_SB_RSP<0>")
	)
	(arc
		(start 89.462864 -255.049274)
		(mid 89.186423 -254.982108)
		(end 88.912192 -255.05791)
		(width 0.088646)
		(layer "In6.Cu")
		(net "M_C_CPU1_SB_RSP<0>")
	)
	(arc
		(start 86.092792 -255.05791)
		(mid 85.905594 -255.108053)
		(end 85.718396 -255.05791)
		(width 0.088646)
		(layer "In6.Cu")
		(net "M_C_CPU1_SB_RSP<0>")
	)
	(arc
		(start 97.183194 -254.733552)
		(mid 96.869017 -254.469706)
		(end 96.52635 -254.244094)
		(width 0.088646)
		(layer "In6.Cu")
		(net "M_C_CPU1_SB_RSP<0>")
	)
	(arc
		(start 85.718396 -255.05791)
		(mid 85.677466 -255.030877)
		(end 85.640418 -254.998728)
		(width 0.088646)
		(layer "In6.Cu")
		(net "M_C_CPU1_SB_RSP<0>")
	)
	(arc
		(start 87.972392 -255.05791)
		(mid 87.785194 -255.108053)
		(end 87.597996 -255.05791)
		(width 0.088646)
		(layer "In6.Cu")
		(net "M_C_CPU1_SB_RSP<0>")
	)
	(arc
		(start 86.658196 -255.05791)
		(mid 86.375494 -254.982168)
		(end 86.092792 -255.05791)
		(width 0.088646)
		(layer "In6.Cu")
		(net "M_C_CPU1_SB_RSP<0>")
	)
	(segment
		(start 34.055812 -246.616728)
		(end 34.871914 -246.616728)
		(width 0.20066)
		(layer "F.Cu")
		(net "M_C_CPU1_SB_PAR")
	)
	(segment
		(start 32.51708 -247.04167)
		(end 32.666178 -246.892572)
		(width 0.20066)
		(layer "F.Cu")
		(net "M_C_CPU1_SB_PAR")
	)
	(segment
		(start 32.666178 -246.892572)
		(end 32.666178 -246.740934)
		(width 0.20066)
		(layer "F.Cu")
		(net "M_C_CPU1_SB_PAR")
	)
	(segment
		(start 32.794702 -246.61241)
		(end 33.189926 -246.61241)
		(width 0.20066)
		(layer "F.Cu")
		(net "M_C_CPU1_SB_PAR")
	)
	(segment
		(start 33.189926 -246.61241)
		(end 33.401762 -246.824246)
		(width 0.20066)
		(layer "F.Cu")
		(net "M_C_CPU1_SB_PAR")
	)
	(segment
		(start 33.848294 -246.824246)
		(end 34.055812 -246.616728)
		(width 0.20066)
		(layer "F.Cu")
		(net "M_C_CPU1_SB_PAR")
	)
	(segment
		(start 29.899864 -247.04167)
		(end 31.972758 -247.04167)
		(width 0.1016)
		(layer "F.Cu")
		(net "M_C_CPU1_SB_PAR")
	)
	(segment
		(start 29.29382 -247.055894)
		(end 29.647642 -247.055894)
		(width 0.20066)
		(layer "F.Cu")
		(net "M_C_CPU1_SB_PAR")
	)
	(segment
		(start 94.254066 -245.27256)
		(end 94.253812 -245.272306)
		(width 0.20066)
		(layer "F.Cu")
		(net "M_C_CPU1_SB_PAR")
	)
	(segment
		(start 29.151326 -246.9134)
		(end 29.29382 -247.055894)
		(width 0.20066)
		(layer "F.Cu")
		(net "M_C_CPU1_SB_PAR")
	)
	(segment
		(start 33.401762 -246.824246)
		(end 33.848294 -246.824246)
		(width 0.20066)
		(layer "F.Cu")
		(net "M_C_CPU1_SB_PAR")
	)
	(segment
		(start 32.666178 -246.740934)
		(end 32.794702 -246.61241)
		(width 0.20066)
		(layer "F.Cu")
		(net "M_C_CPU1_SB_PAR")
	)
	(segment
		(start 29.661866 -247.04167)
		(end 29.899864 -247.04167)
		(width 0.101854)
		(layer "F.Cu")
		(net "M_C_CPU1_SB_PAR")
	)
	(segment
		(start 94.253812 -245.272306)
		(end 94.253812 -244.73662)
		(width 0.20066)
		(layer "F.Cu")
		(net "M_C_CPU1_SB_PAR")
	)
	(segment
		(start 35.976814 -246.616728)
		(end 34.871914 -246.616728)
		(width 0.20066)
		(layer "F.Cu")
		(net "M_C_CPU1_SB_PAR")
	)
	(segment
		(start 29.647642 -247.055894)
		(end 29.661866 -247.04167)
		(width 0.101854)
		(layer "F.Cu")
		(net "M_C_CPU1_SB_PAR")
	)
	(segment
		(start 29.151326 -246.742712)
		(end 29.151326 -246.9134)
		(width 0.20066)
		(layer "F.Cu")
		(net "M_C_CPU1_SB_PAR")
	)
	(segment
		(start 31.972758 -247.04167)
		(end 32.51708 -247.04167)
		(width 0.20066)
		(layer "F.Cu")
		(net "M_C_CPU1_SB_PAR")
	)
	(segment
		(start 27.328114 -246.616728)
		(end 29.025342 -246.616728)
		(width 0.20066)
		(layer "F.Cu")
		(net "M_C_CPU1_SB_PAR")
	)
	(segment
		(start 29.025342 -246.616728)
		(end 29.151326 -246.742712)
		(width 0.20066)
		(layer "F.Cu")
		(net "M_C_CPU1_SB_PAR")
	)
	(segment
		(start 86.170516 -246.3546)
		(end 86.170516 -246.364506)
		(width 0.088646)
		(layer "In4.Cu")
		(net "M_C_CPU1_SB_PAR")
	)
	(segment
		(start 53.664104 -246.903748)
		(end 53.481224 -246.720868)
		(width 0.18288)
		(layer "In4.Cu")
		(net "M_C_CPU1_SB_PAR")
	)
	(segment
		(start 89.367614 -245.060978)
		(end 89.352882 -245.052342)
		(width 0.088646)
		(layer "In4.Cu")
		(net "M_C_CPU1_SB_PAR")
	)
	(segment
		(start 56.931814 -246.928132)
		(end 55.913528 -246.928132)
		(width 0.18288)
		(layer "In4.Cu")
		(net "M_C_CPU1_SB_PAR")
	)
	(segment
		(start 63.282576 -246.793004)
		(end 62.794388 -247.281192)
		(width 0.18288)
		(layer "In4.Cu")
		(net "M_C_CPU1_SB_PAR")
	)
	(segment
		(start 93.529912 -244.428772)
		(end 93.501464 -244.412262)
		(width 0.088646)
		(layer "In4.Cu")
		(net "M_C_CPU1_SB_PAR")
	)
	(segment
		(start 90.307668 -245.060978)
		(end 90.297254 -245.054882)
		(width 0.088646)
		(layer "In4.Cu")
		(net "M_C_CPU1_SB_PAR")
	)
	(segment
		(start 57.622694 -247.26773)
		(end 57.271412 -247.26773)
		(width 0.18288)
		(layer "In4.Cu")
		(net "M_C_CPU1_SB_PAR")
	)
	(segment
		(start 51.880516 -247.22836)
		(end 51.693826 -247.04167)
		(width 0.18288)
		(layer "In4.Cu")
		(net "M_C_CPU1_SB_PAR")
	)
	(segment
		(start 66.793364 -246.793004)
		(end 63.282576 -246.793004)
		(width 0.18288)
		(layer "In4.Cu")
		(net "M_C_CPU1_SB_PAR")
	)
	(segment
		(start 53.481224 -246.720868)
		(end 53.156104 -246.720868)
		(width 0.18288)
		(layer "In4.Cu")
		(net "M_C_CPU1_SB_PAR")
	)
	(segment
		(start 57.271412 -247.26773)
		(end 56.931814 -246.928132)
		(width 0.18288)
		(layer "In4.Cu")
		(net "M_C_CPU1_SB_PAR")
	)
	(segment
		(start 39.086536 -247.04167)
		(end 38.785546 -246.74068)
		(width 0.18288)
		(layer "In4.Cu")
		(net "M_C_CPU1_SB_PAR")
	)
	(segment
		(start 91.247468 -244.412262)
		(end 90.96121 -244.577616)
		(width 0.088646)
		(layer "In4.Cu")
		(net "M_C_CPU1_SB_PAR")
	)
	(segment
		(start 85.991954 -246.683784)
		(end 85.983064 -246.688864)
		(width 0.088646)
		(layer "In4.Cu")
		(net "M_C_CPU1_SB_PAR")
	)
	(segment
		(start 90.869262 -244.73662)
		(end 90.869262 -244.736874)
		(width 0.088646)
		(layer "In4.Cu")
		(net "M_C_CPU1_SB_PAR")
	)
	(segment
		(start 52.973224 -247.04548)
		(end 52.790344 -247.22836)
		(width 0.18288)
		(layer "In4.Cu")
		(net "M_C_CPU1_SB_PAR")
	)
	(segment
		(start 86.461854 -245.869968)
		(end 86.452964 -245.875048)
		(width 0.088646)
		(layer "In4.Cu")
		(net "M_C_CPU1_SB_PAR")
	)
	(segment
		(start 88.427306 -245.060724)
		(end 88.427814 -245.060978)
		(width 0.088646)
		(layer "In4.Cu")
		(net "M_C_CPU1_SB_PAR")
	)
	(segment
		(start 61.075062 -246.699278)
		(end 60.749942 -246.699278)
		(width 0.18288)
		(layer "In4.Cu")
		(net "M_C_CPU1_SB_PAR")
	)
	(segment
		(start 88.80221 -245.060978)
		(end 88.801194 -245.06174)
		(width 0.088646)
		(layer "In4.Cu")
		(net "M_C_CPU1_SB_PAR")
	)
	(segment
		(start 60.567062 -246.882158)
		(end 60.567062 -247.098312)
		(width 0.18288)
		(layer "In4.Cu")
		(net "M_C_CPU1_SB_PAR")
	)
	(segment
		(start 53.846984 -247.22836)
		(end 53.664104 -247.04548)
		(width 0.18288)
		(layer "In4.Cu")
		(net "M_C_CPU1_SB_PAR")
	)
	(segment
		(start 60.567062 -247.098312)
		(end 60.384182 -247.281192)
		(width 0.18288)
		(layer "In4.Cu")
		(net "M_C_CPU1_SB_PAR")
	)
	(segment
		(start 51.693826 -247.04167)
		(end 39.086536 -247.04167)
		(width 0.18288)
		(layer "In4.Cu")
		(net "M_C_CPU1_SB_PAR")
	)
	(segment
		(start 55.6133 -247.22836)
		(end 53.846984 -247.22836)
		(width 0.18288)
		(layer "In4.Cu")
		(net "M_C_CPU1_SB_PAR")
	)
	(segment
		(start 87.488014 -245.060978)
		(end 87.473282 -245.052342)
		(width 0.088646)
		(layer "In4.Cu")
		(net "M_C_CPU1_SB_PAR")
	)
	(segment
		(start 67.073018 -246.51335)
		(end 66.793364 -246.793004)
		(width 0.18288)
		(layer "In4.Cu")
		(net "M_C_CPU1_SB_PAR")
	)
	(segment
		(start 52.973224 -246.903748)
		(end 52.973224 -247.04548)
		(width 0.18288)
		(layer "In4.Cu")
		(net "M_C_CPU1_SB_PAR")
	)
	(segment
		(start 52.790344 -247.22836)
		(end 51.880516 -247.22836)
		(width 0.18288)
		(layer "In4.Cu")
		(net "M_C_CPU1_SB_PAR")
	)
	(segment
		(start 59.67095 -247.281192)
		(end 59.31789 -246.928132)
		(width 0.18288)
		(layer "In4.Cu")
		(net "M_C_CPU1_SB_PAR")
	)
	(segment
		(start 55.913528 -246.928132)
		(end 55.6133 -247.22836)
		(width 0.18288)
		(layer "In4.Cu")
		(net "M_C_CPU1_SB_PAR")
	)
	(segment
		(start 57.962292 -246.928132)
		(end 57.622694 -247.26773)
		(width 0.18288)
		(layer "In4.Cu")
		(net "M_C_CPU1_SB_PAR")
	)
	(segment
		(start 61.440822 -247.281192)
		(end 61.257942 -247.098312)
		(width 0.18288)
		(layer "In4.Cu")
		(net "M_C_CPU1_SB_PAR")
	)
	(segment
		(start 86.640416 -245.528592)
		(end 86.640416 -245.55069)
		(width 0.088646)
		(layer "In4.Cu")
		(net "M_C_CPU1_SB_PAR")
	)
	(segment
		(start 61.257942 -247.098312)
		(end 61.257942 -246.882158)
		(width 0.18288)
		(layer "In4.Cu")
		(net "M_C_CPU1_SB_PAR")
	)
	(segment
		(start 83.39709 -246.51335)
		(end 83.06435 -246.51335)
		(width 0.088646)
		(layer "In4.Cu")
		(net "M_C_CPU1_SB_PAR")
	)
	(segment
		(start 61.257942 -246.882158)
		(end 61.075062 -246.699278)
		(width 0.18288)
		(layer "In4.Cu")
		(net "M_C_CPU1_SB_PAR")
	)
	(segment
		(start 93.127068 -244.412262)
		(end 93.126814 -244.412262)
		(width 0.088646)
		(layer "In4.Cu")
		(net "M_C_CPU1_SB_PAR")
	)
	(segment
		(start 88.427814 -245.060978)
		(end 88.413082 -245.052342)
		(width 0.088646)
		(layer "In4.Cu")
		(net "M_C_CPU1_SB_PAR")
	)
	(segment
		(start 94.253812 -244.73662)
		(end 93.529912 -244.428772)
		(width 0.088646)
		(layer "In4.Cu")
		(net "M_C_CPU1_SB_PAR")
	)
	(segment
		(start 62.794388 -247.281192)
		(end 61.440822 -247.281192)
		(width 0.18288)
		(layer "In4.Cu")
		(net "M_C_CPU1_SB_PAR")
	)
	(segment
		(start 60.749942 -246.699278)
		(end 60.567062 -246.882158)
		(width 0.18288)
		(layer "In4.Cu")
		(net "M_C_CPU1_SB_PAR")
	)
	(segment
		(start 83.62315 -246.73941)
		(end 83.39709 -246.51335)
		(width 0.088646)
		(layer "In4.Cu")
		(net "M_C_CPU1_SB_PAR")
	)
	(segment
		(start 83.916266 -246.73941)
		(end 83.62315 -246.73941)
		(width 0.088646)
		(layer "In4.Cu")
		(net "M_C_CPU1_SB_PAR")
	)
	(segment
		(start 60.384182 -247.281192)
		(end 59.67095 -247.281192)
		(width 0.18288)
		(layer "In4.Cu")
		(net "M_C_CPU1_SB_PAR")
	)
	(segment
		(start 37.732462 -246.74068)
		(end 37.41801 -247.055132)
		(width 0.18288)
		(layer "In4.Cu")
		(net "M_C_CPU1_SB_PAR")
	)
	(segment
		(start 59.31789 -246.928132)
		(end 57.962292 -246.928132)
		(width 0.18288)
		(layer "In4.Cu")
		(net "M_C_CPU1_SB_PAR")
	)
	(segment
		(start 83.06435 -246.51335)
		(end 67.073018 -246.51335)
		(width 0.18288)
		(layer "In4.Cu")
		(net "M_C_CPU1_SB_PAR")
	)
	(segment
		(start 53.664104 -247.04548)
		(end 53.664104 -246.903748)
		(width 0.18288)
		(layer "In4.Cu")
		(net "M_C_CPU1_SB_PAR")
	)
	(segment
		(start 92.187268 -244.412262)
		(end 92.176854 -244.418358)
		(width 0.088646)
		(layer "In4.Cu")
		(net "M_C_CPU1_SB_PAR")
	)
	(segment
		(start 38.785546 -246.74068)
		(end 37.732462 -246.74068)
		(width 0.18288)
		(layer "In4.Cu")
		(net "M_C_CPU1_SB_PAR")
	)
	(segment
		(start 37.41801 -247.055132)
		(end 36.415218 -247.055132)
		(width 0.18288)
		(layer "In4.Cu")
		(net "M_C_CPU1_SB_PAR")
	)
	(segment
		(start 53.156104 -246.720868)
		(end 52.973224 -246.903748)
		(width 0.18288)
		(layer "In4.Cu")
		(net "M_C_CPU1_SB_PAR")
	)
	(segment
		(start 36.415218 -247.055132)
		(end 35.976814 -246.616728)
		(width 0.18288)
		(layer "In4.Cu")
		(net "M_C_CPU1_SB_PAR")
	)
	(arc
		(start 88.801194 -245.06174)
		(mid 88.614098 -245.111274)
		(end 88.427306 -245.060724)
		(width 0.088646)
		(layer "In4.Cu")
		(net "M_C_CPU1_SB_PAR")
	)
	(arc
		(start 93.126814 -244.412262)
		(mid 92.844256 -244.487911)
		(end 92.561664 -244.412262)
		(width 0.088646)
		(layer "In4.Cu")
		(net "M_C_CPU1_SB_PAR")
	)
	(arc
		(start 92.176854 -244.418358)
		(mid 91.898422 -244.488204)
		(end 91.62161 -244.412262)
		(width 0.088646)
		(layer "In4.Cu")
		(net "M_C_CPU1_SB_PAR")
	)
	(arc
		(start 87.473282 -245.052342)
		(mid 87.196841 -244.985176)
		(end 86.92261 -245.060978)
		(width 0.088646)
		(layer "In4.Cu")
		(net "M_C_CPU1_SB_PAR")
	)
	(arc
		(start 84.668868 -246.688864)
		(mid 84.386166 -246.613088)
		(end 84.103464 -246.688864)
		(width 0.088646)
		(layer "In4.Cu")
		(net "M_C_CPU1_SB_PAR")
	)
	(arc
		(start 89.352882 -245.052342)
		(mid 89.076441 -244.985176)
		(end 88.80221 -245.060978)
		(width 0.088646)
		(layer "In4.Cu")
		(net "M_C_CPU1_SB_PAR")
	)
	(arc
		(start 86.640416 -245.55069)
		(mid 86.592737 -245.73359)
		(end 86.461854 -245.869968)
		(width 0.088646)
		(layer "In4.Cu")
		(net "M_C_CPU1_SB_PAR")
	)
	(arc
		(start 89.74201 -245.060978)
		(mid 89.554812 -245.111121)
		(end 89.367614 -245.060978)
		(width 0.088646)
		(layer "In4.Cu")
		(net "M_C_CPU1_SB_PAR")
	)
	(arc
		(start 85.043264 -246.688864)
		(mid 84.856066 -246.739007)
		(end 84.668868 -246.688864)
		(width 0.088646)
		(layer "In4.Cu")
		(net "M_C_CPU1_SB_PAR")
	)
	(arc
		(start 90.682064 -245.060978)
		(mid 90.494866 -245.111121)
		(end 90.307668 -245.060978)
		(width 0.088646)
		(layer "In4.Cu")
		(net "M_C_CPU1_SB_PAR")
	)
	(arc
		(start 85.983064 -246.688864)
		(mid 85.795866 -246.739007)
		(end 85.608668 -246.688864)
		(width 0.088646)
		(layer "In4.Cu")
		(net "M_C_CPU1_SB_PAR")
	)
	(arc
		(start 90.297254 -245.054882)
		(mid 90.018822 -244.985068)
		(end 89.74201 -245.060978)
		(width 0.088646)
		(layer "In4.Cu")
		(net "M_C_CPU1_SB_PAR")
	)
	(arc
		(start 88.413082 -245.052342)
		(mid 88.136641 -244.985176)
		(end 87.86241 -245.060978)
		(width 0.088646)
		(layer "In4.Cu")
		(net "M_C_CPU1_SB_PAR")
	)
	(arc
		(start 85.608668 -246.688864)
		(mid 85.325966 -246.613088)
		(end 85.043264 -246.688864)
		(width 0.088646)
		(layer "In4.Cu")
		(net "M_C_CPU1_SB_PAR")
	)
	(arc
		(start 90.96121 -244.577616)
		(mid 90.89388 -244.644774)
		(end 90.869262 -244.73662)
		(width 0.088646)
		(layer "In4.Cu")
		(net "M_C_CPU1_SB_PAR")
	)
	(arc
		(start 91.62161 -244.412262)
		(mid 91.434556 -244.362212)
		(end 91.247468 -244.412262)
		(width 0.088646)
		(layer "In4.Cu")
		(net "M_C_CPU1_SB_PAR")
	)
	(arc
		(start 86.92261 -245.060978)
		(mid 86.721328 -245.258465)
		(end 86.640416 -245.528592)
		(width 0.088646)
		(layer "In4.Cu")
		(net "M_C_CPU1_SB_PAR")
	)
	(arc
		(start 93.501464 -244.412262)
		(mid 93.314266 -244.362085)
		(end 93.127068 -244.412262)
		(width 0.088646)
		(layer "In4.Cu")
		(net "M_C_CPU1_SB_PAR")
	)
	(arc
		(start 87.86241 -245.060978)
		(mid 87.675212 -245.111121)
		(end 87.488014 -245.060978)
		(width 0.088646)
		(layer "In4.Cu")
		(net "M_C_CPU1_SB_PAR")
	)
	(arc
		(start 90.869262 -244.736874)
		(mid 90.819098 -244.924012)
		(end 90.682064 -245.060978)
		(width 0.088646)
		(layer "In4.Cu")
		(net "M_C_CPU1_SB_PAR")
	)
	(arc
		(start 86.452964 -245.875048)
		(mid 86.248629 -246.077653)
		(end 86.170516 -246.3546)
		(width 0.088646)
		(layer "In4.Cu")
		(net "M_C_CPU1_SB_PAR")
	)
	(arc
		(start 86.170516 -246.364506)
		(mid 86.122837 -246.547406)
		(end 85.991954 -246.683784)
		(width 0.088646)
		(layer "In4.Cu")
		(net "M_C_CPU1_SB_PAR")
	)
	(arc
		(start 92.561664 -244.412262)
		(mid 92.374466 -244.362119)
		(end 92.187268 -244.412262)
		(width 0.088646)
		(layer "In4.Cu")
		(net "M_C_CPU1_SB_PAR")
	)
	(arc
		(start 84.103464 -246.688864)
		(mid 84.013192 -246.726463)
		(end 83.916266 -246.73941)
		(width 0.088646)
		(layer "In4.Cu")
		(net "M_C_CPU1_SB_PAR")
	)
	(segment
		(start 26.45029 -238.541814)
		(end 28.52928 -238.541814)
		(width 0.1016)
		(layer "F.Cu")
		(net "M_C_CPU1_SB_DQS_DP<9>")
	)
	(segment
		(start 92.374466 -240.389156)
		(end 92.374466 -239.85347)
		(width 0.20066)
		(layer "F.Cu")
		(net "M_C_CPU1_SB_DQS_DP<9>")
	)
	(segment
		(start 24.452072 -237.855506)
		(end 25.088088 -238.280702)
		(width 0.20066)
		(layer "F.Cu")
		(net "M_C_CPU1_SB_DQS_DP<9>")
	)
	(segment
		(start 29.268166 -238.280702)
		(end 29.693362 -237.855506)
		(width 0.20066)
		(layer "F.Cu")
		(net "M_C_CPU1_SB_DQS_DP<9>")
	)
	(segment
		(start 25.088088 -238.280702)
		(end 25.715214 -238.280702)
		(width 0.20066)
		(layer "F.Cu")
		(net "M_C_CPU1_SB_DQS_DP<9>")
	)
	(segment
		(start 31.876746 -238.116618)
		(end 30.771846 -238.116618)
		(width 0.20066)
		(layer "F.Cu")
		(net "M_C_CPU1_SB_DQS_DP<9>")
	)
	(segment
		(start 23.228046 -238.116618)
		(end 23.766018 -238.116618)
		(width 0.20066)
		(layer "F.Cu")
		(net "M_C_CPU1_SB_DQS_DP<9>")
	)
	(segment
		(start 24.02713 -237.855506)
		(end 24.452072 -237.855506)
		(width 0.20066)
		(layer "F.Cu")
		(net "M_C_CPU1_SB_DQS_DP<9>")
	)
	(segment
		(start 28.590494 -238.541814)
		(end 28.681172 -238.541814)
		(width 0.20066)
		(layer "F.Cu")
		(net "M_C_CPU1_SB_DQS_DP<9>")
	)
	(segment
		(start 29.962094 -237.855506)
		(end 30.223206 -238.116618)
		(width 0.20066)
		(layer "F.Cu")
		(net "M_C_CPU1_SB_DQS_DP<9>")
	)
	(segment
		(start 25.976326 -238.541814)
		(end 26.065734 -238.541814)
		(width 0.20066)
		(layer "F.Cu")
		(net "M_C_CPU1_SB_DQS_DP<9>")
	)
	(segment
		(start 28.681172 -238.541814)
		(end 28.942284 -238.280702)
		(width 0.20066)
		(layer "F.Cu")
		(net "M_C_CPU1_SB_DQS_DP<9>")
	)
	(segment
		(start 23.766018 -238.116618)
		(end 24.02713 -237.855506)
		(width 0.20066)
		(layer "F.Cu")
		(net "M_C_CPU1_SB_DQS_DP<9>")
	)
	(segment
		(start 26.065734 -238.541814)
		(end 26.45029 -238.541814)
		(width 0.101854)
		(layer "F.Cu")
		(net "M_C_CPU1_SB_DQS_DP<9>")
	)
	(segment
		(start 92.374466 -239.85347)
		(end 92.374212 -239.853216)
		(width 0.20066)
		(layer "F.Cu")
		(net "M_C_CPU1_SB_DQS_DP<9>")
	)
	(segment
		(start 25.715214 -238.280702)
		(end 25.976326 -238.541814)
		(width 0.20066)
		(layer "F.Cu")
		(net "M_C_CPU1_SB_DQS_DP<9>")
	)
	(segment
		(start 28.942284 -238.280702)
		(end 29.268166 -238.280702)
		(width 0.20066)
		(layer "F.Cu")
		(net "M_C_CPU1_SB_DQS_DP<9>")
	)
	(segment
		(start 30.223206 -238.116618)
		(end 30.771846 -238.116618)
		(width 0.20066)
		(layer "F.Cu")
		(net "M_C_CPU1_SB_DQS_DP<9>")
	)
	(segment
		(start 28.52928 -238.541814)
		(end 28.590494 -238.541814)
		(width 0.101854)
		(layer "F.Cu")
		(net "M_C_CPU1_SB_DQS_DP<9>")
	)
	(segment
		(start 29.693362 -237.855506)
		(end 29.962094 -237.855506)
		(width 0.20066)
		(layer "F.Cu")
		(net "M_C_CPU1_SB_DQS_DP<9>")
	)
	(segment
		(start 87.407496 -240.351564)
		(end 87.392764 -240.342928)
		(width 0.088646)
		(layer "In4.Cu")
		(net "M_C_CPU1_SB_DQS_DP<9>")
	)
	(segment
		(start 32.839914 -237.54969)
		(end 32.554418 -237.835186)
		(width 0.18288)
		(layer "In4.Cu")
		(net "M_C_CPU1_SB_DQS_DP<9>")
	)
	(segment
		(start 32.554418 -237.835186)
		(end 32.158178 -237.835186)
		(width 0.18288)
		(layer "In4.Cu")
		(net "M_C_CPU1_SB_DQS_DP<9>")
	)
	(segment
		(start 47.41418 -239.12576)
		(end 47.147988 -239.391952)
		(width 0.18288)
		(layer "In4.Cu")
		(net "M_C_CPU1_SB_DQS_DP<9>")
	)
	(segment
		(start 40.012366 -238.272574)
		(end 36.521644 -238.272574)
		(width 0.18288)
		(layer "In4.Cu")
		(net "M_C_CPU1_SB_DQS_DP<9>")
	)
	(segment
		(start 47.147988 -239.391952)
		(end 46.77156 -239.391952)
		(width 0.18288)
		(layer "In4.Cu")
		(net "M_C_CPU1_SB_DQS_DP<9>")
	)
	(segment
		(start 90.98661 -240.222278)
		(end 90.76309 -240.351056)
		(width 0.088646)
		(layer "In4.Cu")
		(net "M_C_CPU1_SB_DQS_DP<9>")
	)
	(segment
		(start 46.496224 -239.116616)
		(end 46.001432 -239.116616)
		(width 0.18288)
		(layer "In4.Cu")
		(net "M_C_CPU1_SB_DQS_DP<9>")
	)
	(segment
		(start 84.280756 -241.525806)
		(end 83.157568 -241.525806)
		(width 0.088646)
		(layer "In4.Cu")
		(net "M_C_CPU1_SB_DQS_DP<9>")
	)
	(segment
		(start 35.7759 -238.541814)
		(end 35.500564 -238.266478)
		(width 0.18288)
		(layer "In4.Cu")
		(net "M_C_CPU1_SB_DQS_DP<9>")
	)
	(segment
		(start 36.521644 -238.272574)
		(end 36.252404 -238.541814)
		(width 0.18288)
		(layer "In4.Cu")
		(net "M_C_CPU1_SB_DQS_DP<9>")
	)
	(segment
		(start 70.37451 -241.58575)
		(end 67.666108 -238.877348)
		(width 0.18288)
		(layer "In4.Cu")
		(net "M_C_CPU1_SB_DQS_DP<9>")
	)
	(segment
		(start 67.666108 -238.877348)
		(end 63.291212 -238.877348)
		(width 0.18288)
		(layer "In4.Cu")
		(net "M_C_CPU1_SB_DQS_DP<9>")
	)
	(segment
		(start 61.696346 -238.496856)
		(end 60.77839 -237.5789)
		(width 0.18288)
		(layer "In4.Cu")
		(net "M_C_CPU1_SB_DQS_DP<9>")
	)
	(segment
		(start 83.064096 -241.58575)
		(end 70.37451 -241.58575)
		(width 0.18288)
		(layer "In4.Cu")
		(net "M_C_CPU1_SB_DQS_DP<9>")
	)
	(segment
		(start 83.097624 -241.58575)
		(end 83.064096 -241.58575)
		(width 0.088646)
		(layer "In4.Cu")
		(net "M_C_CPU1_SB_DQS_DP<9>")
	)
	(segment
		(start 50.046128 -238.266478)
		(end 49.186846 -239.12576)
		(width 0.18288)
		(layer "In4.Cu")
		(net "M_C_CPU1_SB_DQS_DP<9>")
	)
	(segment
		(start 46.001432 -239.116616)
		(end 44.526962 -237.642146)
		(width 0.18288)
		(layer "In4.Cu")
		(net "M_C_CPU1_SB_DQS_DP<9>")
	)
	(segment
		(start 55.322724 -238.280956)
		(end 51.502818 -238.280956)
		(width 0.18288)
		(layer "In4.Cu")
		(net "M_C_CPU1_SB_DQS_DP<9>")
	)
	(segment
		(start 88.901524 -240.340642)
		(end 88.897714 -240.342928)
		(width 0.088646)
		(layer "In4.Cu")
		(net "M_C_CPU1_SB_DQS_DP<9>")
	)
	(segment
		(start 86.830916 -240.667286)
		(end 86.830916 -240.677192)
		(width 0.088646)
		(layer "In4.Cu")
		(net "M_C_CPU1_SB_DQS_DP<9>")
	)
	(segment
		(start 92.033852 -239.943132)
		(end 91.608656 -240.18494)
		(width 0.088646)
		(layer "In4.Cu")
		(net "M_C_CPU1_SB_DQS_DP<9>")
	)
	(segment
		(start 62.91072 -238.496856)
		(end 61.696346 -238.496856)
		(width 0.18288)
		(layer "In4.Cu")
		(net "M_C_CPU1_SB_DQS_DP<9>")
	)
	(segment
		(start 36.252404 -238.541814)
		(end 35.7759 -238.541814)
		(width 0.18288)
		(layer "In4.Cu")
		(net "M_C_CPU1_SB_DQS_DP<9>")
	)
	(segment
		(start 89.287096 -240.351564)
		(end 89.272364 -240.342928)
		(width 0.088646)
		(layer "In4.Cu")
		(net "M_C_CPU1_SB_DQS_DP<9>")
	)
	(segment
		(start 84.668868 -241.156744)
		(end 84.659978 -241.162078)
		(width 0.088646)
		(layer "In4.Cu")
		(net "M_C_CPU1_SB_DQS_DP<9>")
	)
	(segment
		(start 35.500564 -238.266478)
		(end 34.902902 -238.266478)
		(width 0.18288)
		(layer "In4.Cu")
		(net "M_C_CPU1_SB_DQS_DP<9>")
	)
	(segment
		(start 91.347036 -240.219738)
		(end 91.34221 -240.222278)
		(width 0.088646)
		(layer "In4.Cu")
		(net "M_C_CPU1_SB_DQS_DP<9>")
	)
	(segment
		(start 49.186846 -239.12576)
		(end 47.41418 -239.12576)
		(width 0.18288)
		(layer "In4.Cu")
		(net "M_C_CPU1_SB_DQS_DP<9>")
	)
	(segment
		(start 51.24196 -238.541814)
		(end 50.866548 -238.541814)
		(width 0.18288)
		(layer "In4.Cu")
		(net "M_C_CPU1_SB_DQS_DP<9>")
	)
	(segment
		(start 83.157568 -241.525806)
		(end 83.097624 -241.58575)
		(width 0.088646)
		(layer "In4.Cu")
		(net "M_C_CPU1_SB_DQS_DP<9>")
	)
	(segment
		(start 89.272364 -240.342928)
		(end 89.272364 -240.342674)
		(width 0.088646)
		(layer "In4.Cu")
		(net "M_C_CPU1_SB_DQS_DP<9>")
	)
	(segment
		(start 40.642794 -237.642146)
		(end 40.012366 -238.272574)
		(width 0.18288)
		(layer "In4.Cu")
		(net "M_C_CPU1_SB_DQS_DP<9>")
	)
	(segment
		(start 32.158178 -237.835186)
		(end 31.876746 -238.116618)
		(width 0.18288)
		(layer "In4.Cu")
		(net "M_C_CPU1_SB_DQS_DP<9>")
	)
	(segment
		(start 88.903556 -240.339372)
		(end 88.901524 -240.340642)
		(width 0.088646)
		(layer "In4.Cu")
		(net "M_C_CPU1_SB_DQS_DP<9>")
	)
	(segment
		(start 50.866548 -238.541814)
		(end 50.591212 -238.266478)
		(width 0.18288)
		(layer "In4.Cu")
		(net "M_C_CPU1_SB_DQS_DP<9>")
	)
	(segment
		(start 51.502818 -238.280956)
		(end 51.24196 -238.541814)
		(width 0.18288)
		(layer "In4.Cu")
		(net "M_C_CPU1_SB_DQS_DP<9>")
	)
	(segment
		(start 56.02478 -237.5789)
		(end 55.322724 -238.280956)
		(width 0.18288)
		(layer "In4.Cu")
		(net "M_C_CPU1_SB_DQS_DP<9>")
	)
	(segment
		(start 34.902902 -238.266478)
		(end 34.186114 -237.54969)
		(width 0.18288)
		(layer "In4.Cu")
		(net "M_C_CPU1_SB_DQS_DP<9>")
	)
	(segment
		(start 90.21191 -240.342674)
		(end 90.212164 -240.342928)
		(width 0.088646)
		(layer "In4.Cu")
		(net "M_C_CPU1_SB_DQS_DP<9>")
	)
	(segment
		(start 91.404186 -240.226596)
		(end 91.347036 -240.219738)
		(width 0.088646)
		(layer "In4.Cu")
		(net "M_C_CPU1_SB_DQS_DP<9>")
	)
	(segment
		(start 84.590636 -241.21618)
		(end 84.280756 -241.525806)
		(width 0.088646)
		(layer "In4.Cu")
		(net "M_C_CPU1_SB_DQS_DP<9>")
	)
	(segment
		(start 84.632292 -241.18062)
		(end 84.618322 -241.191542)
		(width 0.088646)
		(layer "In4.Cu")
		(net "M_C_CPU1_SB_DQS_DP<9>")
	)
	(segment
		(start 91.34221 -240.222278)
		(end 90.98661 -240.222278)
		(width 0.088646)
		(layer "In4.Cu")
		(net "M_C_CPU1_SB_DQS_DP<9>")
	)
	(segment
		(start 44.526962 -237.642146)
		(end 40.642794 -237.642146)
		(width 0.18288)
		(layer "In4.Cu")
		(net "M_C_CPU1_SB_DQS_DP<9>")
	)
	(segment
		(start 34.186114 -237.54969)
		(end 32.839914 -237.54969)
		(width 0.18288)
		(layer "In4.Cu")
		(net "M_C_CPU1_SB_DQS_DP<9>")
	)
	(segment
		(start 63.291212 -238.877348)
		(end 62.91072 -238.496856)
		(width 0.18288)
		(layer "In4.Cu")
		(net "M_C_CPU1_SB_DQS_DP<9>")
	)
	(segment
		(start 50.591212 -238.266478)
		(end 50.046128 -238.266478)
		(width 0.18288)
		(layer "In4.Cu")
		(net "M_C_CPU1_SB_DQS_DP<9>")
	)
	(segment
		(start 46.77156 -239.391952)
		(end 46.496224 -239.116616)
		(width 0.18288)
		(layer "In4.Cu")
		(net "M_C_CPU1_SB_DQS_DP<9>")
	)
	(segment
		(start 88.897714 -240.342928)
		(end 88.893142 -240.345468)
		(width 0.088646)
		(layer "In4.Cu")
		(net "M_C_CPU1_SB_DQS_DP<9>")
	)
	(segment
		(start 60.77839 -237.5789)
		(end 56.02478 -237.5789)
		(width 0.18288)
		(layer "In4.Cu")
		(net "M_C_CPU1_SB_DQS_DP<9>")
	)
	(arc
		(start 84.618322 -241.191542)
		(mid 84.604175 -241.20352)
		(end 84.590636 -241.21618)
		(width 0.088646)
		(layer "In4.Cu")
		(net "M_C_CPU1_SB_DQS_DP<9>")
	)
	(arc
		(start 91.608656 -240.18494)
		(mid 91.509814 -240.22245)
		(end 91.404186 -240.226596)
		(width 0.088646)
		(layer "In4.Cu")
		(net "M_C_CPU1_SB_DQS_DP<9>")
	)
	(arc
		(start 89.272364 -240.342674)
		(mid 89.08841 -240.292579)
		(end 88.903556 -240.339372)
		(width 0.088646)
		(layer "In4.Cu")
		(net "M_C_CPU1_SB_DQS_DP<9>")
	)
	(arc
		(start 88.332564 -240.342928)
		(mid 88.145366 -240.292785)
		(end 87.958168 -240.342928)
		(width 0.088646)
		(layer "In4.Cu")
		(net "M_C_CPU1_SB_DQS_DP<9>")
	)
	(arc
		(start 87.958168 -240.342928)
		(mid 87.683939 -240.418853)
		(end 87.407496 -240.351564)
		(width 0.088646)
		(layer "In4.Cu")
		(net "M_C_CPU1_SB_DQS_DP<9>")
	)
	(arc
		(start 86.830916 -240.677192)
		(mid 86.544041 -241.159277)
		(end 85.983064 -241.156744)
		(width 0.088646)
		(layer "In4.Cu")
		(net "M_C_CPU1_SB_DQS_DP<9>")
	)
	(arc
		(start 90.212164 -240.342928)
		(mid 90.024966 -240.292785)
		(end 89.837768 -240.342928)
		(width 0.088646)
		(layer "In4.Cu")
		(net "M_C_CPU1_SB_DQS_DP<9>")
	)
	(arc
		(start 86.83117 -240.652554)
		(mid 86.830973 -240.659919)
		(end 86.830916 -240.667286)
		(width 0.088646)
		(layer "In4.Cu")
		(net "M_C_CPU1_SB_DQS_DP<9>")
	)
	(arc
		(start 87.392764 -240.342928)
		(mid 87.024702 -240.339354)
		(end 86.83117 -240.652554)
		(width 0.088646)
		(layer "In4.Cu")
		(net "M_C_CPU1_SB_DQS_DP<9>")
	)
	(arc
		(start 85.608668 -241.156744)
		(mid 85.325966 -241.23252)
		(end 85.043264 -241.156744)
		(width 0.088646)
		(layer "In4.Cu")
		(net "M_C_CPU1_SB_DQS_DP<9>")
	)
	(arc
		(start 85.043264 -241.156744)
		(mid 84.856066 -241.106601)
		(end 84.668868 -241.156744)
		(width 0.088646)
		(layer "In4.Cu")
		(net "M_C_CPU1_SB_DQS_DP<9>")
	)
	(arc
		(start 92.374212 -239.853216)
		(mid 92.198191 -239.876053)
		(end 92.033852 -239.943132)
		(width 0.088646)
		(layer "In4.Cu")
		(net "M_C_CPU1_SB_DQS_DP<9>")
	)
	(arc
		(start 84.659978 -241.162078)
		(mid 84.645931 -241.171044)
		(end 84.632292 -241.18062)
		(width 0.088646)
		(layer "In4.Cu")
		(net "M_C_CPU1_SB_DQS_DP<9>")
	)
	(arc
		(start 90.76309 -240.351056)
		(mid 90.486425 -240.418527)
		(end 90.21191 -240.342674)
		(width 0.088646)
		(layer "In4.Cu")
		(net "M_C_CPU1_SB_DQS_DP<9>")
	)
	(arc
		(start 85.983064 -241.156744)
		(mid 85.795866 -241.106601)
		(end 85.608668 -241.156744)
		(width 0.088646)
		(layer "In4.Cu")
		(net "M_C_CPU1_SB_DQS_DP<9>")
	)
	(arc
		(start 88.893142 -240.345468)
		(mid 88.612507 -240.418636)
		(end 88.332564 -240.342928)
		(width 0.088646)
		(layer "In4.Cu")
		(net "M_C_CPU1_SB_DQS_DP<9>")
	)
	(arc
		(start 89.837768 -240.342928)
		(mid 89.563539 -240.418853)
		(end 89.287096 -240.351564)
		(width 0.088646)
		(layer "In4.Cu")
		(net "M_C_CPU1_SB_DQS_DP<9>")
	)
	(segment
		(start 34.382202 -199.01662)
		(end 34.871914 -199.01662)
		(width 0.20066)
		(layer "F.Cu")
		(net "M_C_CPU1_SB_DQS_DP<8>")
	)
	(segment
		(start 29.18079 -198.855584)
		(end 29.450284 -198.58609)
		(width 0.20066)
		(layer "F.Cu")
		(net "M_C_CPU1_SB_DQS_DP<8>")
	)
	(segment
		(start 28.398216 -199.277986)
		(end 28.820618 -198.855584)
		(width 0.20066)
		(layer "F.Cu")
		(net "M_C_CPU1_SB_DQS_DP<8>")
	)
	(segment
		(start 31.972504 -198.591678)
		(end 31.972758 -198.591932)
		(width 0.1016)
		(layer "F.Cu")
		(net "M_C_CPU1_SB_DQS_DP<8>")
	)
	(segment
		(start 32.375348 -198.853044)
		(end 32.8803 -198.853044)
		(width 0.20066)
		(layer "F.Cu")
		(net "M_C_CPU1_SB_DQS_DP<8>")
	)
	(segment
		(start 27.328114 -199.01662)
		(end 27.802586 -199.01662)
		(width 0.20066)
		(layer "F.Cu")
		(net "M_C_CPU1_SB_DQS_DP<8>")
	)
	(segment
		(start 97.543112 -228.1809)
		(end 97.543112 -227.645214)
		(width 0.20066)
		(layer "F.Cu")
		(net "M_C_CPU1_SB_DQS_DP<8>")
	)
	(segment
		(start 27.802586 -199.01662)
		(end 28.063952 -199.277986)
		(width 0.20066)
		(layer "F.Cu")
		(net "M_C_CPU1_SB_DQS_DP<8>")
	)
	(segment
		(start 32.8803 -198.853044)
		(end 33.516316 -199.277986)
		(width 0.20066)
		(layer "F.Cu")
		(net "M_C_CPU1_SB_DQS_DP<8>")
	)
	(segment
		(start 33.516316 -199.277986)
		(end 34.120836 -199.277986)
		(width 0.20066)
		(layer "F.Cu")
		(net "M_C_CPU1_SB_DQS_DP<8>")
	)
	(segment
		(start 31.972758 -198.591932)
		(end 32.114236 -198.591932)
		(width 0.20066)
		(layer "F.Cu")
		(net "M_C_CPU1_SB_DQS_DP<8>")
	)
	(segment
		(start 34.120836 -199.277986)
		(end 34.382202 -199.01662)
		(width 0.20066)
		(layer "F.Cu")
		(net "M_C_CPU1_SB_DQS_DP<8>")
	)
	(segment
		(start 28.063952 -199.277986)
		(end 28.398216 -199.277986)
		(width 0.20066)
		(layer "F.Cu")
		(net "M_C_CPU1_SB_DQS_DP<8>")
	)
	(segment
		(start 29.647642 -198.58609)
		(end 29.65323 -198.591678)
		(width 0.101854)
		(layer "F.Cu")
		(net "M_C_CPU1_SB_DQS_DP<8>")
	)
	(segment
		(start 28.820618 -198.855584)
		(end 29.18079 -198.855584)
		(width 0.20066)
		(layer "F.Cu")
		(net "M_C_CPU1_SB_DQS_DP<8>")
	)
	(segment
		(start 97.543112 -227.645214)
		(end 97.543366 -227.64496)
		(width 0.20066)
		(layer "F.Cu")
		(net "M_C_CPU1_SB_DQS_DP<8>")
	)
	(segment
		(start 32.114236 -198.591932)
		(end 32.375348 -198.853044)
		(width 0.20066)
		(layer "F.Cu")
		(net "M_C_CPU1_SB_DQS_DP<8>")
	)
	(segment
		(start 29.89453 -198.591678)
		(end 31.972504 -198.591678)
		(width 0.1016)
		(layer "F.Cu")
		(net "M_C_CPU1_SB_DQS_DP<8>")
	)
	(segment
		(start 29.65323 -198.591678)
		(end 29.89453 -198.591678)
		(width 0.101854)
		(layer "F.Cu")
		(net "M_C_CPU1_SB_DQS_DP<8>")
	)
	(segment
		(start 29.450284 -198.58609)
		(end 29.647642 -198.58609)
		(width 0.20066)
		(layer "F.Cu")
		(net "M_C_CPU1_SB_DQS_DP<8>")
	)
	(segment
		(start 35.976814 -199.01662)
		(end 34.871914 -199.01662)
		(width 0.20066)
		(layer "F.Cu")
		(net "M_C_CPU1_SB_DQS_DP<8>")
	)
	(segment
		(start 47.165514 -196.890894)
		(end 46.771814 -196.890894)
		(width 0.18288)
		(layer "In6.Cu")
		(net "M_C_CPU1_SB_DQS_DP<8>")
	)
	(segment
		(start 88.897968 -226.341686)
		(end 88.889078 -226.336606)
		(width 0.088646)
		(layer "In6.Cu")
		(net "M_C_CPU1_SB_DQS_DP<8>")
	)
	(segment
		(start 36.172902 -198.820532)
		(end 35.976814 -199.01662)
		(width 0.18288)
		(layer "In6.Cu")
		(net "M_C_CPU1_SB_DQS_DP<8>")
	)
	(segment
		(start 81.056988 -221.909132)
		(end 81.056988 -219.637356)
		(width 0.18288)
		(layer "In6.Cu")
		(net "M_C_CPU1_SB_DQS_DP<8>")
	)
	(segment
		(start 82.50301 -222.294958)
		(end 82.479642 -222.294958)
		(width 0.088646)
		(layer "In6.Cu")
		(net "M_C_CPU1_SB_DQS_DP<8>")
	)
	(segment
		(start 42.389806 -197.998842)
		(end 41.789858 -197.998842)
		(width 0.18288)
		(layer "In6.Cu")
		(net "M_C_CPU1_SB_DQS_DP<8>")
	)
	(segment
		(start 40.815514 -198.020432)
		(end 40.319452 -198.020432)
		(width 0.18288)
		(layer "In6.Cu")
		(net "M_C_CPU1_SB_DQS_DP<8>")
	)
	(segment
		(start 83.631024 -222.722186)
		(end 83.26374 -222.354902)
		(width 0.088646)
		(layer "In6.Cu")
		(net "M_C_CPU1_SB_DQS_DP<8>")
	)
	(segment
		(start 36.300664 -198.820532)
		(end 36.172902 -198.820532)
		(width 0.18288)
		(layer "In6.Cu")
		(net "M_C_CPU1_SB_DQS_DP<8>")
	)
	(segment
		(start 69.683122 -204.407262)
		(end 66.671444 -201.395584)
		(width 0.18288)
		(layer "In6.Cu")
		(net "M_C_CPU1_SB_DQS_DP<8>")
	)
	(segment
		(start 88.710516 -226.017328)
		(end 88.710516 -225.998786)
		(width 0.088646)
		(layer "In6.Cu")
		(net "M_C_CPU1_SB_DQS_DP<8>")
	)
	(segment
		(start 55.743602 -197.323202)
		(end 54.736238 -196.315838)
		(width 0.18288)
		(layer "In6.Cu")
		(net "M_C_CPU1_SB_DQS_DP<8>")
	)
	(segment
		(start 60.218574 -197.956932)
		(end 59.806078 -197.956932)
		(width 0.18288)
		(layer "In6.Cu")
		(net "M_C_CPU1_SB_DQS_DP<8>")
	)
	(segment
		(start 82.562954 -222.354902)
		(end 82.50301 -222.294958)
		(width 0.088646)
		(layer "In6.Cu")
		(net "M_C_CPU1_SB_DQS_DP<8>")
	)
	(segment
		(start 83.26374 -222.354902)
		(end 82.562954 -222.354902)
		(width 0.088646)
		(layer "In6.Cu")
		(net "M_C_CPU1_SB_DQS_DP<8>")
	)
	(segment
		(start 96.51619 -227.278438)
		(end 96.511364 -227.275898)
		(width 0.088646)
		(layer "In6.Cu")
		(net "M_C_CPU1_SB_DQS_DP<8>")
	)
	(segment
		(start 89.287096 -226.33305)
		(end 89.272364 -226.341686)
		(width 0.088646)
		(layer "In6.Cu")
		(net "M_C_CPU1_SB_DQS_DP<8>")
	)
	(segment
		(start 66.671444 -201.395584)
		(end 65.701672 -201.395584)
		(width 0.18288)
		(layer "In6.Cu")
		(net "M_C_CPU1_SB_DQS_DP<8>")
	)
	(segment
		(start 62.76721 -199.821546)
		(end 61.599572 -199.337676)
		(width 0.18288)
		(layer "In6.Cu")
		(net "M_C_CPU1_SB_DQS_DP<8>")
	)
	(segment
		(start 94.066614 -227.155502)
		(end 94.051882 -227.146866)
		(width 0.088646)
		(layer "In6.Cu")
		(net "M_C_CPU1_SB_DQS_DP<8>")
	)
	(segment
		(start 91.717368 -226.341686)
		(end 91.706954 -226.33559)
		(width 0.088646)
		(layer "In6.Cu")
		(net "M_C_CPU1_SB_DQS_DP<8>")
	)
	(segment
		(start 36.483544 -198.637652)
		(end 36.300664 -198.820532)
		(width 0.18288)
		(layer "In6.Cu")
		(net "M_C_CPU1_SB_DQS_DP<8>")
	)
	(segment
		(start 90.222578 -226.33559)
		(end 90.212164 -226.341686)
		(width 0.088646)
		(layer "In6.Cu")
		(net "M_C_CPU1_SB_DQS_DP<8>")
	)
	(segment
		(start 97.203006 -227.555044)
		(end 96.77781 -227.313236)
		(width 0.088646)
		(layer "In6.Cu")
		(net "M_C_CPU1_SB_DQS_DP<8>")
	)
	(segment
		(start 45.26407 -196.552566)
		(end 44.369228 -196.552566)
		(width 0.18288)
		(layer "In6.Cu")
		(net "M_C_CPU1_SB_DQS_DP<8>")
	)
	(segment
		(start 36.483544 -198.469504)
		(end 36.483544 -198.637652)
		(width 0.18288)
		(layer "In6.Cu")
		(net "M_C_CPU1_SB_DQS_DP<8>")
	)
	(segment
		(start 46.771814 -196.890894)
		(end 46.497494 -197.165214)
		(width 0.18288)
		(layer "In6.Cu")
		(net "M_C_CPU1_SB_DQS_DP<8>")
	)
	(segment
		(start 40.319452 -198.020432)
		(end 40.061642 -197.762622)
		(width 0.18288)
		(layer "In6.Cu")
		(net "M_C_CPU1_SB_DQS_DP<8>")
	)
	(segment
		(start 65.701672 -201.395584)
		(end 64.127634 -199.821546)
		(width 0.18288)
		(layer "In6.Cu")
		(net "M_C_CPU1_SB_DQS_DP<8>")
	)
	(segment
		(start 41.509442 -197.718426)
		(end 41.11752 -197.718426)
		(width 0.18288)
		(layer "In6.Cu")
		(net "M_C_CPU1_SB_DQS_DP<8>")
	)
	(segment
		(start 88.240616 -225.203258)
		(end 88.240616 -225.193352)
		(width 0.088646)
		(layer "In6.Cu")
		(net "M_C_CPU1_SB_DQS_DP<8>")
	)
	(segment
		(start 95.006414 -227.155502)
		(end 94.991682 -227.146866)
		(width 0.088646)
		(layer "In6.Cu")
		(net "M_C_CPU1_SB_DQS_DP<8>")
	)
	(segment
		(start 64.127634 -199.821546)
		(end 62.76721 -199.821546)
		(width 0.18288)
		(layer "In6.Cu")
		(net "M_C_CPU1_SB_DQS_DP<8>")
	)
	(segment
		(start 92.939616 -226.831144)
		(end 92.939616 -226.821238)
		(width 0.088646)
		(layer "In6.Cu")
		(net "M_C_CPU1_SB_DQS_DP<8>")
	)
	(segment
		(start 51.528218 -196.315838)
		(end 51.25466 -196.04228)
		(width 0.18288)
		(layer "In6.Cu")
		(net "M_C_CPU1_SB_DQS_DP<8>")
	)
	(segment
		(start 51.25466 -196.04228)
		(end 50.872644 -196.04228)
		(width 0.18288)
		(layer "In6.Cu")
		(net "M_C_CPU1_SB_DQS_DP<8>")
	)
	(segment
		(start 59.172348 -197.323202)
		(end 55.743602 -197.323202)
		(width 0.18288)
		(layer "In6.Cu")
		(net "M_C_CPU1_SB_DQS_DP<8>")
	)
	(segment
		(start 41.789858 -197.998842)
		(end 41.509442 -197.718426)
		(width 0.18288)
		(layer "In6.Cu")
		(net "M_C_CPU1_SB_DQS_DP<8>")
	)
	(segment
		(start 96.155764 -227.275898)
		(end 95.936054 -227.149406)
		(width 0.088646)
		(layer "In6.Cu")
		(net "M_C_CPU1_SB_DQS_DP<8>")
	)
	(segment
		(start 45.876718 -197.165214)
		(end 45.26407 -196.552566)
		(width 0.18288)
		(layer "In6.Cu")
		(net "M_C_CPU1_SB_DQS_DP<8>")
	)
	(segment
		(start 84.85632 -224.638108)
		(end 84.730844 -224.638108)
		(width 0.088646)
		(layer "In6.Cu")
		(net "M_C_CPU1_SB_DQS_DP<8>")
	)
	(segment
		(start 50.872644 -196.04228)
		(end 50.586386 -196.328538)
		(width 0.18288)
		(layer "In6.Cu")
		(net "M_C_CPU1_SB_DQS_DP<8>")
	)
	(segment
		(start 84.730844 -224.638108)
		(end 83.631024 -223.538288)
		(width 0.088646)
		(layer "In6.Cu")
		(net "M_C_CPU1_SB_DQS_DP<8>")
	)
	(segment
		(start 46.497494 -197.165214)
		(end 45.876718 -197.165214)
		(width 0.18288)
		(layer "In6.Cu")
		(net "M_C_CPU1_SB_DQS_DP<8>")
	)
	(segment
		(start 50.586386 -196.328538)
		(end 50.374042 -196.328538)
		(width 0.18288)
		(layer "In6.Cu")
		(net "M_C_CPU1_SB_DQS_DP<8>")
	)
	(segment
		(start 43.00601 -197.382384)
		(end 42.389806 -197.998842)
		(width 0.18288)
		(layer "In6.Cu")
		(net "M_C_CPU1_SB_DQS_DP<8>")
	)
	(segment
		(start 93.127068 -227.155502)
		(end 93.118178 -227.150422)
		(width 0.088646)
		(layer "In6.Cu")
		(net "M_C_CPU1_SB_DQS_DP<8>")
	)
	(segment
		(start 61.599572 -199.337676)
		(end 60.218574 -197.956932)
		(width 0.18288)
		(layer "In6.Cu")
		(net "M_C_CPU1_SB_DQS_DP<8>")
	)
	(segment
		(start 54.736238 -196.315838)
		(end 51.528218 -196.315838)
		(width 0.18288)
		(layer "In6.Cu")
		(net "M_C_CPU1_SB_DQS_DP<8>")
	)
	(segment
		(start 84.892642 -224.639124)
		(end 84.89188 -224.639124)
		(width 0.088646)
		(layer "In6.Cu")
		(net "M_C_CPU1_SB_DQS_DP<8>")
	)
	(segment
		(start 81.442814 -222.294958)
		(end 81.056988 -221.909132)
		(width 0.18288)
		(layer "In6.Cu")
		(net "M_C_CPU1_SB_DQS_DP<8>")
	)
	(segment
		(start 81.056988 -219.637356)
		(end 72.36968 -210.950048)
		(width 0.18288)
		(layer "In6.Cu")
		(net "M_C_CPU1_SB_DQS_DP<8>")
	)
	(segment
		(start 41.11752 -197.718426)
		(end 40.815514 -198.020432)
		(width 0.18288)
		(layer "In6.Cu")
		(net "M_C_CPU1_SB_DQS_DP<8>")
	)
	(segment
		(start 43.916346 -197.005194)
		(end 43.00601 -197.382384)
		(width 0.18288)
		(layer "In6.Cu")
		(net "M_C_CPU1_SB_DQS_DP<8>")
	)
	(segment
		(start 50.374042 -196.328538)
		(end 48.360076 -197.162674)
		(width 0.18288)
		(layer "In6.Cu")
		(net "M_C_CPU1_SB_DQS_DP<8>")
	)
	(segment
		(start 59.806078 -197.956932)
		(end 59.172348 -197.323202)
		(width 0.18288)
		(layer "In6.Cu")
		(net "M_C_CPU1_SB_DQS_DP<8>")
	)
	(segment
		(start 40.061642 -197.762622)
		(end 37.190426 -197.762622)
		(width 0.18288)
		(layer "In6.Cu")
		(net "M_C_CPU1_SB_DQS_DP<8>")
	)
	(segment
		(start 47.437294 -197.162674)
		(end 47.165514 -196.890894)
		(width 0.18288)
		(layer "In6.Cu")
		(net "M_C_CPU1_SB_DQS_DP<8>")
	)
	(segment
		(start 48.360076 -197.162674)
		(end 47.437294 -197.162674)
		(width 0.18288)
		(layer "In6.Cu")
		(net "M_C_CPU1_SB_DQS_DP<8>")
	)
	(segment
		(start 86.078568 -224.7138)
		(end 86.068154 -224.707704)
		(width 0.088646)
		(layer "In6.Cu")
		(net "M_C_CPU1_SB_DQS_DP<8>")
	)
	(segment
		(start 83.631024 -223.538288)
		(end 83.631024 -222.722186)
		(width 0.088646)
		(layer "In6.Cu")
		(net "M_C_CPU1_SB_DQS_DP<8>")
	)
	(segment
		(start 96.57334 -227.27158)
		(end 96.51619 -227.278438)
		(width 0.088646)
		(layer "In6.Cu")
		(net "M_C_CPU1_SB_DQS_DP<8>")
	)
	(segment
		(start 96.511364 -227.275898)
		(end 96.155764 -227.275898)
		(width 0.088646)
		(layer "In6.Cu")
		(net "M_C_CPU1_SB_DQS_DP<8>")
	)
	(segment
		(start 88.428068 -225.527616)
		(end 88.419178 -225.522536)
		(width 0.088646)
		(layer "In6.Cu")
		(net "M_C_CPU1_SB_DQS_DP<8>")
	)
	(segment
		(start 37.190426 -197.762622)
		(end 36.483544 -198.469504)
		(width 0.18288)
		(layer "In6.Cu")
		(net "M_C_CPU1_SB_DQS_DP<8>")
	)
	(segment
		(start 72.36968 -210.950048)
		(end 69.683122 -204.407262)
		(width 0.18288)
		(layer "In6.Cu")
		(net "M_C_CPU1_SB_DQS_DP<8>")
	)
	(segment
		(start 82.479642 -222.294958)
		(end 81.442814 -222.294958)
		(width 0.18288)
		(layer "In6.Cu")
		(net "M_C_CPU1_SB_DQS_DP<8>")
	)
	(segment
		(start 93.126814 -227.155502)
		(end 93.127068 -227.155502)
		(width 0.088646)
		(layer "In6.Cu")
		(net "M_C_CPU1_SB_DQS_DP<8>")
	)
	(segment
		(start 44.369228 -196.552566)
		(end 43.916346 -197.005194)
		(width 0.18288)
		(layer "In6.Cu")
		(net "M_C_CPU1_SB_DQS_DP<8>")
	)
	(arc
		(start 92.091764 -226.341686)
		(mid 91.904566 -226.391829)
		(end 91.717368 -226.341686)
		(width 0.088646)
		(layer "In6.Cu")
		(net "M_C_CPU1_SB_DQS_DP<8>")
	)
	(arc
		(start 92.939616 -226.821238)
		(mid 92.861505 -226.544289)
		(end 92.657168 -226.341686)
		(width 0.088646)
		(layer "In6.Cu")
		(net "M_C_CPU1_SB_DQS_DP<8>")
	)
	(arc
		(start 85.51291 -224.7138)
		(mid 85.325712 -224.763943)
		(end 85.138514 -224.7138)
		(width 0.088646)
		(layer "In6.Cu")
		(net "M_C_CPU1_SB_DQS_DP<8>")
	)
	(arc
		(start 86.068154 -224.707704)
		(mid 85.789722 -224.637858)
		(end 85.51291 -224.7138)
		(width 0.088646)
		(layer "In6.Cu")
		(net "M_C_CPU1_SB_DQS_DP<8>")
	)
	(arc
		(start 91.706954 -226.33559)
		(mid 91.428522 -226.265744)
		(end 91.15171 -226.341686)
		(width 0.088646)
		(layer "In6.Cu")
		(net "M_C_CPU1_SB_DQS_DP<8>")
	)
	(arc
		(start 85.138514 -224.7138)
		(mid 85.019883 -224.66228)
		(end 84.892642 -224.639124)
		(width 0.088646)
		(layer "In6.Cu")
		(net "M_C_CPU1_SB_DQS_DP<8>")
	)
	(arc
		(start 89.272364 -226.341686)
		(mid 89.085166 -226.391829)
		(end 88.897968 -226.341686)
		(width 0.088646)
		(layer "In6.Cu")
		(net "M_C_CPU1_SB_DQS_DP<8>")
	)
	(arc
		(start 96.77781 -227.313236)
		(mid 96.678968 -227.275726)
		(end 96.57334 -227.27158)
		(width 0.088646)
		(layer "In6.Cu")
		(net "M_C_CPU1_SB_DQS_DP<8>")
	)
	(arc
		(start 93.50121 -227.155502)
		(mid 93.314012 -227.205645)
		(end 93.126814 -227.155502)
		(width 0.088646)
		(layer "In6.Cu")
		(net "M_C_CPU1_SB_DQS_DP<8>")
	)
	(arc
		(start 90.212164 -226.341686)
		(mid 90.024966 -226.391829)
		(end 89.837768 -226.341686)
		(width 0.088646)
		(layer "In6.Cu")
		(net "M_C_CPU1_SB_DQS_DP<8>")
	)
	(arc
		(start 84.89188 -224.639124)
		(mid 84.874108 -224.63834)
		(end 84.85632 -224.638108)
		(width 0.088646)
		(layer "In6.Cu")
		(net "M_C_CPU1_SB_DQS_DP<8>")
	)
	(arc
		(start 88.710516 -225.998786)
		(mid 88.630354 -225.726597)
		(end 88.428068 -225.527616)
		(width 0.088646)
		(layer "In6.Cu")
		(net "M_C_CPU1_SB_DQS_DP<8>")
	)
	(arc
		(start 97.543366 -227.64496)
		(mid 97.367345 -227.622123)
		(end 97.203006 -227.555044)
		(width 0.088646)
		(layer "In6.Cu")
		(net "M_C_CPU1_SB_DQS_DP<8>")
	)
	(arc
		(start 94.991682 -227.146866)
		(mid 94.715207 -227.079546)
		(end 94.44101 -227.155502)
		(width 0.088646)
		(layer "In6.Cu")
		(net "M_C_CPU1_SB_DQS_DP<8>")
	)
	(arc
		(start 94.051882 -227.146866)
		(mid 93.775407 -227.079546)
		(end 93.50121 -227.155502)
		(width 0.088646)
		(layer "In6.Cu")
		(net "M_C_CPU1_SB_DQS_DP<8>")
	)
	(arc
		(start 88.240616 -225.193352)
		(mid 88.162505 -224.916403)
		(end 87.958168 -224.7138)
		(width 0.088646)
		(layer "In6.Cu")
		(net "M_C_CPU1_SB_DQS_DP<8>")
	)
	(arc
		(start 88.889078 -226.336606)
		(mid 88.758164 -226.200246)
		(end 88.710516 -226.017328)
		(width 0.088646)
		(layer "In6.Cu")
		(net "M_C_CPU1_SB_DQS_DP<8>")
	)
	(arc
		(start 90.777314 -226.341686)
		(mid 90.500755 -226.265943)
		(end 90.222578 -226.33559)
		(width 0.088646)
		(layer "In6.Cu")
		(net "M_C_CPU1_SB_DQS_DP<8>")
	)
	(arc
		(start 94.44101 -227.155502)
		(mid 94.253812 -227.205645)
		(end 94.066614 -227.155502)
		(width 0.088646)
		(layer "In6.Cu")
		(net "M_C_CPU1_SB_DQS_DP<8>")
	)
	(arc
		(start 86.452964 -224.7138)
		(mid 86.265766 -224.763943)
		(end 86.078568 -224.7138)
		(width 0.088646)
		(layer "In6.Cu")
		(net "M_C_CPU1_SB_DQS_DP<8>")
	)
	(arc
		(start 89.837768 -226.341686)
		(mid 89.563569 -226.265851)
		(end 89.287096 -226.33305)
		(width 0.088646)
		(layer "In6.Cu")
		(net "M_C_CPU1_SB_DQS_DP<8>")
	)
	(arc
		(start 95.936054 -227.149406)
		(mid 95.657622 -227.07956)
		(end 95.38081 -227.155502)
		(width 0.088646)
		(layer "In6.Cu")
		(net "M_C_CPU1_SB_DQS_DP<8>")
	)
	(arc
		(start 91.15171 -226.341686)
		(mid 90.964512 -226.391829)
		(end 90.777314 -226.341686)
		(width 0.088646)
		(layer "In6.Cu")
		(net "M_C_CPU1_SB_DQS_DP<8>")
	)
	(arc
		(start 95.38081 -227.155502)
		(mid 95.193612 -227.205645)
		(end 95.006414 -227.155502)
		(width 0.088646)
		(layer "In6.Cu")
		(net "M_C_CPU1_SB_DQS_DP<8>")
	)
	(arc
		(start 87.018368 -224.7138)
		(mid 86.735666 -224.638024)
		(end 86.452964 -224.7138)
		(width 0.088646)
		(layer "In6.Cu")
		(net "M_C_CPU1_SB_DQS_DP<8>")
	)
	(arc
		(start 92.657168 -226.341686)
		(mid 92.374466 -226.26591)
		(end 92.091764 -226.341686)
		(width 0.088646)
		(layer "In6.Cu")
		(net "M_C_CPU1_SB_DQS_DP<8>")
	)
	(arc
		(start 88.419178 -225.522536)
		(mid 88.288264 -225.386176)
		(end 88.240616 -225.203258)
		(width 0.088646)
		(layer "In6.Cu")
		(net "M_C_CPU1_SB_DQS_DP<8>")
	)
	(arc
		(start 87.958168 -224.7138)
		(mid 87.675466 -224.638024)
		(end 87.392764 -224.7138)
		(width 0.088646)
		(layer "In6.Cu")
		(net "M_C_CPU1_SB_DQS_DP<8>")
	)
	(arc
		(start 93.118178 -227.150422)
		(mid 92.987264 -227.014062)
		(end 92.939616 -226.831144)
		(width 0.088646)
		(layer "In6.Cu")
		(net "M_C_CPU1_SB_DQS_DP<8>")
	)
	(arc
		(start 87.392764 -224.7138)
		(mid 87.205566 -224.763943)
		(end 87.018368 -224.7138)
		(width 0.088646)
		(layer "In6.Cu")
		(net "M_C_CPU1_SB_DQS_DP<8>")
	)
	(segment
		(start 28.820618 -208.205578)
		(end 29.18079 -208.205578)
		(width 0.20066)
		(layer "F.Cu")
		(net "M_C_CPU1_SB_DQS_DP<7>")
	)
	(segment
		(start 94.253812 -230.622348)
		(end 94.253812 -230.086662)
		(width 0.20066)
		(layer "F.Cu")
		(net "M_C_CPU1_SB_DQS_DP<7>")
	)
	(segment
		(start 28.398216 -208.62798)
		(end 28.820618 -208.205578)
		(width 0.20066)
		(layer "F.Cu")
		(net "M_C_CPU1_SB_DQS_DP<7>")
	)
	(segment
		(start 29.89453 -207.941672)
		(end 31.972504 -207.941672)
		(width 0.1016)
		(layer "F.Cu")
		(net "M_C_CPU1_SB_DQS_DP<7>")
	)
	(segment
		(start 28.063952 -208.62798)
		(end 28.398216 -208.62798)
		(width 0.20066)
		(layer "F.Cu")
		(net "M_C_CPU1_SB_DQS_DP<7>")
	)
	(segment
		(start 29.65323 -207.941672)
		(end 29.89453 -207.941672)
		(width 0.101854)
		(layer "F.Cu")
		(net "M_C_CPU1_SB_DQS_DP<7>")
	)
	(segment
		(start 27.328114 -208.366614)
		(end 27.802586 -208.366614)
		(width 0.20066)
		(layer "F.Cu")
		(net "M_C_CPU1_SB_DQS_DP<7>")
	)
	(segment
		(start 29.450284 -207.936084)
		(end 29.647642 -207.936084)
		(width 0.20066)
		(layer "F.Cu")
		(net "M_C_CPU1_SB_DQS_DP<7>")
	)
	(segment
		(start 32.8803 -208.203038)
		(end 33.516316 -208.62798)
		(width 0.20066)
		(layer "F.Cu")
		(net "M_C_CPU1_SB_DQS_DP<7>")
	)
	(segment
		(start 29.647642 -207.936084)
		(end 29.65323 -207.941672)
		(width 0.101854)
		(layer "F.Cu")
		(net "M_C_CPU1_SB_DQS_DP<7>")
	)
	(segment
		(start 34.382202 -208.366614)
		(end 34.871914 -208.366614)
		(width 0.20066)
		(layer "F.Cu")
		(net "M_C_CPU1_SB_DQS_DP<7>")
	)
	(segment
		(start 94.254066 -230.622602)
		(end 94.253812 -230.622348)
		(width 0.20066)
		(layer "F.Cu")
		(net "M_C_CPU1_SB_DQS_DP<7>")
	)
	(segment
		(start 31.972504 -207.941672)
		(end 31.972758 -207.941926)
		(width 0.1016)
		(layer "F.Cu")
		(net "M_C_CPU1_SB_DQS_DP<7>")
	)
	(segment
		(start 32.114236 -207.941926)
		(end 32.375348 -208.203038)
		(width 0.20066)
		(layer "F.Cu")
		(net "M_C_CPU1_SB_DQS_DP<7>")
	)
	(segment
		(start 31.972758 -207.941926)
		(end 32.114236 -207.941926)
		(width 0.20066)
		(layer "F.Cu")
		(net "M_C_CPU1_SB_DQS_DP<7>")
	)
	(segment
		(start 27.802586 -208.366614)
		(end 28.063952 -208.62798)
		(width 0.20066)
		(layer "F.Cu")
		(net "M_C_CPU1_SB_DQS_DP<7>")
	)
	(segment
		(start 34.120836 -208.62798)
		(end 34.382202 -208.366614)
		(width 0.20066)
		(layer "F.Cu")
		(net "M_C_CPU1_SB_DQS_DP<7>")
	)
	(segment
		(start 33.516316 -208.62798)
		(end 34.120836 -208.62798)
		(width 0.20066)
		(layer "F.Cu")
		(net "M_C_CPU1_SB_DQS_DP<7>")
	)
	(segment
		(start 32.375348 -208.203038)
		(end 32.8803 -208.203038)
		(width 0.20066)
		(layer "F.Cu")
		(net "M_C_CPU1_SB_DQS_DP<7>")
	)
	(segment
		(start 35.976814 -208.366614)
		(end 34.871914 -208.366614)
		(width 0.20066)
		(layer "F.Cu")
		(net "M_C_CPU1_SB_DQS_DP<7>")
	)
	(segment
		(start 29.18079 -208.205578)
		(end 29.450284 -207.936084)
		(width 0.20066)
		(layer "F.Cu")
		(net "M_C_CPU1_SB_DQS_DP<7>")
	)
	(segment
		(start 71.720964 -222.030036)
		(end 67.51574 -211.882736)
		(width 0.18288)
		(layer "In4.Cu")
		(net "M_C_CPU1_SB_DQS_DP<7>")
	)
	(segment
		(start 51.273456 -209.641694)
		(end 50.87239 -209.641694)
		(width 0.18288)
		(layer "In4.Cu")
		(net "M_C_CPU1_SB_DQS_DP<7>")
	)
	(segment
		(start 62.059058 -209.320638)
		(end 55.710328 -209.320638)
		(width 0.18288)
		(layer "In4.Cu")
		(net "M_C_CPU1_SB_DQS_DP<7>")
	)
	(segment
		(start 48.985932 -210.786726)
		(end 47.43069 -210.786726)
		(width 0.18288)
		(layer "In4.Cu")
		(net "M_C_CPU1_SB_DQS_DP<7>")
	)
	(segment
		(start 45.835062 -210.733386)
		(end 44.398184 -209.296508)
		(width 0.18288)
		(layer "In4.Cu")
		(net "M_C_CPU1_SB_DQS_DP<7>")
	)
	(segment
		(start 86.467696 -229.588568)
		(end 86.452964 -229.597204)
		(width 0.088646)
		(layer "In4.Cu")
		(net "M_C_CPU1_SB_DQS_DP<7>")
	)
	(segment
		(start 47.135796 -210.491832)
		(end 46.770798 -210.491832)
		(width 0.18288)
		(layer "In4.Cu")
		(net "M_C_CPU1_SB_DQS_DP<7>")
	)
	(segment
		(start 83.377024 -228.639116)
		(end 83.15071 -228.412802)
		(width 0.088646)
		(layer "In4.Cu")
		(net "M_C_CPU1_SB_DQS_DP<7>")
	)
	(segment
		(start 42.41927 -209.296508)
		(end 42.032428 -208.909666)
		(width 0.18288)
		(layer "In4.Cu")
		(net "M_C_CPU1_SB_DQS_DP<7>")
	)
	(segment
		(start 36.238434 -208.628234)
		(end 35.976814 -208.366614)
		(width 0.18288)
		(layer "In4.Cu")
		(net "M_C_CPU1_SB_DQS_DP<7>")
	)
	(segment
		(start 50.599848 -209.914236)
		(end 49.858422 -209.914236)
		(width 0.18288)
		(layer "In4.Cu")
		(net "M_C_CPU1_SB_DQS_DP<7>")
	)
	(segment
		(start 90.777314 -229.597204)
		(end 90.771472 -229.593648)
		(width 0.088646)
		(layer "In4.Cu")
		(net "M_C_CPU1_SB_DQS_DP<7>")
	)
	(segment
		(start 51.544982 -209.91322)
		(end 51.273456 -209.641694)
		(width 0.18288)
		(layer "In4.Cu")
		(net "M_C_CPU1_SB_DQS_DP<7>")
	)
	(segment
		(start 36.788852 -208.628234)
		(end 36.238434 -208.628234)
		(width 0.18288)
		(layer "In4.Cu")
		(net "M_C_CPU1_SB_DQS_DP<7>")
	)
	(segment
		(start 93.940884 -230.086662)
		(end 93.875606 -230.021384)
		(width 0.088646)
		(layer "In4.Cu")
		(net "M_C_CPU1_SB_DQS_DP<7>")
	)
	(segment
		(start 49.858422 -209.914236)
		(end 48.985932 -210.786726)
		(width 0.18288)
		(layer "In4.Cu")
		(net "M_C_CPU1_SB_DQS_DP<7>")
	)
	(segment
		(start 50.87239 -209.641694)
		(end 50.599848 -209.914236)
		(width 0.18288)
		(layer "In4.Cu")
		(net "M_C_CPU1_SB_DQS_DP<7>")
	)
	(segment
		(start 55.710328 -209.320638)
		(end 55.117746 -209.91322)
		(width 0.18288)
		(layer "In4.Cu")
		(net "M_C_CPU1_SB_DQS_DP<7>")
	)
	(segment
		(start 92.106496 -229.588568)
		(end 92.091764 -229.597204)
		(width 0.088646)
		(layer "In4.Cu")
		(net "M_C_CPU1_SB_DQS_DP<7>")
	)
	(segment
		(start 84.38642 -229.64775)
		(end 84.221066 -229.64775)
		(width 0.088646)
		(layer "In4.Cu")
		(net "M_C_CPU1_SB_DQS_DP<7>")
	)
	(segment
		(start 89.837514 -229.597204)
		(end 89.831672 -229.593648)
		(width 0.088646)
		(layer "In4.Cu")
		(net "M_C_CPU1_SB_DQS_DP<7>")
	)
	(segment
		(start 63.453264 -210.714844)
		(end 62.059058 -209.320638)
		(width 0.18288)
		(layer "In4.Cu")
		(net "M_C_CPU1_SB_DQS_DP<7>")
	)
	(segment
		(start 83.377024 -228.803708)
		(end 83.377024 -228.639116)
		(width 0.088646)
		(layer "In4.Cu")
		(net "M_C_CPU1_SB_DQS_DP<7>")
	)
	(segment
		(start 84.573364 -229.597204)
		(end 84.57311 -229.597458)
		(width 0.088646)
		(layer "In4.Cu")
		(net "M_C_CPU1_SB_DQS_DP<7>")
	)
	(segment
		(start 84.588096 -229.588568)
		(end 84.573364 -229.597204)
		(width 0.088646)
		(layer "In4.Cu")
		(net "M_C_CPU1_SB_DQS_DP<7>")
	)
	(segment
		(start 42.032428 -208.909666)
		(end 37.070284 -208.909666)
		(width 0.18288)
		(layer "In4.Cu")
		(net "M_C_CPU1_SB_DQS_DP<7>")
	)
	(segment
		(start 91.717114 -229.597204)
		(end 91.711272 -229.593648)
		(width 0.088646)
		(layer "In4.Cu")
		(net "M_C_CPU1_SB_DQS_DP<7>")
	)
	(segment
		(start 87.407496 -229.588568)
		(end 87.392764 -229.597204)
		(width 0.088646)
		(layer "In4.Cu")
		(net "M_C_CPU1_SB_DQS_DP<7>")
	)
	(segment
		(start 83.15071 -228.412802)
		(end 82.791554 -228.412802)
		(width 0.088646)
		(layer "In4.Cu")
		(net "M_C_CPU1_SB_DQS_DP<7>")
	)
	(segment
		(start 85.527896 -229.588568)
		(end 85.513164 -229.597204)
		(width 0.088646)
		(layer "In4.Cu")
		(net "M_C_CPU1_SB_DQS_DP<7>")
	)
	(segment
		(start 89.843356 -229.600506)
		(end 89.837514 -229.597204)
		(width 0.088646)
		(layer "In4.Cu")
		(net "M_C_CPU1_SB_DQS_DP<7>")
	)
	(segment
		(start 44.398184 -209.296508)
		(end 42.41927 -209.296508)
		(width 0.18288)
		(layer "In4.Cu")
		(net "M_C_CPU1_SB_DQS_DP<7>")
	)
	(segment
		(start 91.722956 -229.600506)
		(end 91.717114 -229.597204)
		(width 0.088646)
		(layer "In4.Cu")
		(net "M_C_CPU1_SB_DQS_DP<7>")
	)
	(segment
		(start 47.43069 -210.786726)
		(end 47.135796 -210.491832)
		(width 0.18288)
		(layer "In4.Cu")
		(net "M_C_CPU1_SB_DQS_DP<7>")
	)
	(segment
		(start 67.51574 -211.882736)
		(end 66.347594 -210.714844)
		(width 0.18288)
		(layer "In4.Cu")
		(net "M_C_CPU1_SB_DQS_DP<7>")
	)
	(segment
		(start 78.043786 -228.353112)
		(end 71.720964 -222.030036)
		(width 0.18288)
		(layer "In4.Cu")
		(net "M_C_CPU1_SB_DQS_DP<7>")
	)
	(segment
		(start 37.070284 -208.909666)
		(end 36.788852 -208.628234)
		(width 0.18288)
		(layer "In4.Cu")
		(net "M_C_CPU1_SB_DQS_DP<7>")
	)
	(segment
		(start 93.046296 -229.588568)
		(end 93.031564 -229.597204)
		(width 0.088646)
		(layer "In4.Cu")
		(net "M_C_CPU1_SB_DQS_DP<7>")
	)
	(segment
		(start 88.903556 -229.600506)
		(end 88.897714 -229.597204)
		(width 0.088646)
		(layer "In4.Cu")
		(net "M_C_CPU1_SB_DQS_DP<7>")
	)
	(segment
		(start 82.708496 -228.353112)
		(end 78.043786 -228.353112)
		(width 0.18288)
		(layer "In4.Cu")
		(net "M_C_CPU1_SB_DQS_DP<7>")
	)
	(segment
		(start 55.117746 -209.91322)
		(end 51.544982 -209.91322)
		(width 0.18288)
		(layer "In4.Cu")
		(net "M_C_CPU1_SB_DQS_DP<7>")
	)
	(segment
		(start 88.897714 -229.597204)
		(end 88.893142 -229.59441)
		(width 0.088646)
		(layer "In4.Cu")
		(net "M_C_CPU1_SB_DQS_DP<7>")
	)
	(segment
		(start 46.529244 -210.733386)
		(end 45.835062 -210.733386)
		(width 0.18288)
		(layer "In4.Cu")
		(net "M_C_CPU1_SB_DQS_DP<7>")
	)
	(segment
		(start 90.783156 -229.600506)
		(end 90.777314 -229.597204)
		(width 0.088646)
		(layer "In4.Cu")
		(net "M_C_CPU1_SB_DQS_DP<7>")
	)
	(segment
		(start 66.347594 -210.714844)
		(end 63.453264 -210.714844)
		(width 0.18288)
		(layer "In4.Cu")
		(net "M_C_CPU1_SB_DQS_DP<7>")
	)
	(segment
		(start 84.221066 -229.64775)
		(end 83.377024 -228.803708)
		(width 0.088646)
		(layer "In4.Cu")
		(net "M_C_CPU1_SB_DQS_DP<7>")
	)
	(segment
		(start 82.731864 -228.353112)
		(end 82.708496 -228.353112)
		(width 0.088646)
		(layer "In4.Cu")
		(net "M_C_CPU1_SB_DQS_DP<7>")
	)
	(segment
		(start 46.770798 -210.491832)
		(end 46.529244 -210.733386)
		(width 0.18288)
		(layer "In4.Cu")
		(net "M_C_CPU1_SB_DQS_DP<7>")
	)
	(segment
		(start 82.791554 -228.412802)
		(end 82.731864 -228.353112)
		(width 0.088646)
		(layer "In4.Cu")
		(net "M_C_CPU1_SB_DQS_DP<7>")
	)
	(segment
		(start 94.253812 -230.086662)
		(end 93.940884 -230.086662)
		(width 0.088646)
		(layer "In4.Cu")
		(net "M_C_CPU1_SB_DQS_DP<7>")
	)
	(arc
		(start 90.212164 -229.597204)
		(mid 90.02821 -229.647333)
		(end 89.843356 -229.600506)
		(width 0.088646)
		(layer "In4.Cu")
		(net "M_C_CPU1_SB_DQS_DP<7>")
	)
	(arc
		(start 87.392764 -229.597204)
		(mid 87.205566 -229.647347)
		(end 87.018368 -229.597204)
		(width 0.088646)
		(layer "In4.Cu")
		(net "M_C_CPU1_SB_DQS_DP<7>")
	)
	(arc
		(start 85.138768 -229.597204)
		(mid 84.864569 -229.521369)
		(end 84.588096 -229.588568)
		(width 0.088646)
		(layer "In4.Cu")
		(net "M_C_CPU1_SB_DQS_DP<7>")
	)
	(arc
		(start 84.57311 -229.597458)
		(mid 84.483064 -229.634844)
		(end 84.38642 -229.64775)
		(width 0.088646)
		(layer "In4.Cu")
		(net "M_C_CPU1_SB_DQS_DP<7>")
	)
	(arc
		(start 88.893142 -229.59441)
		(mid 88.612478 -229.521402)
		(end 88.332564 -229.597204)
		(width 0.088646)
		(layer "In4.Cu")
		(net "M_C_CPU1_SB_DQS_DP<7>")
	)
	(arc
		(start 93.875606 -230.021384)
		(mid 93.874308 -230.01083)
		(end 93.872812 -230.000302)
		(width 0.088646)
		(layer "In4.Cu")
		(net "M_C_CPU1_SB_DQS_DP<7>")
	)
	(arc
		(start 86.078568 -229.597204)
		(mid 85.804369 -229.521369)
		(end 85.527896 -229.588568)
		(width 0.088646)
		(layer "In4.Cu")
		(net "M_C_CPU1_SB_DQS_DP<7>")
	)
	(arc
		(start 86.452964 -229.597204)
		(mid 86.265766 -229.647347)
		(end 86.078568 -229.597204)
		(width 0.088646)
		(layer "In4.Cu")
		(net "M_C_CPU1_SB_DQS_DP<7>")
	)
	(arc
		(start 85.513164 -229.597204)
		(mid 85.325966 -229.647347)
		(end 85.138768 -229.597204)
		(width 0.088646)
		(layer "In4.Cu")
		(net "M_C_CPU1_SB_DQS_DP<7>")
	)
	(arc
		(start 91.151964 -229.597204)
		(mid 90.96801 -229.647333)
		(end 90.783156 -229.600506)
		(width 0.088646)
		(layer "In4.Cu")
		(net "M_C_CPU1_SB_DQS_DP<7>")
	)
	(arc
		(start 93.596968 -229.597204)
		(mid 93.322769 -229.521369)
		(end 93.046296 -229.588568)
		(width 0.088646)
		(layer "In4.Cu")
		(net "M_C_CPU1_SB_DQS_DP<7>")
	)
	(arc
		(start 93.872812 -230.000302)
		(mid 93.78069 -229.767402)
		(end 93.596968 -229.597204)
		(width 0.088646)
		(layer "In4.Cu")
		(net "M_C_CPU1_SB_DQS_DP<7>")
	)
	(arc
		(start 88.332564 -229.597204)
		(mid 88.145366 -229.647347)
		(end 87.958168 -229.597204)
		(width 0.088646)
		(layer "In4.Cu")
		(net "M_C_CPU1_SB_DQS_DP<7>")
	)
	(arc
		(start 91.711272 -229.593648)
		(mid 91.431137 -229.521365)
		(end 91.151964 -229.597204)
		(width 0.088646)
		(layer "In4.Cu")
		(net "M_C_CPU1_SB_DQS_DP<7>")
	)
	(arc
		(start 87.018368 -229.597204)
		(mid 86.744169 -229.521369)
		(end 86.467696 -229.588568)
		(width 0.088646)
		(layer "In4.Cu")
		(net "M_C_CPU1_SB_DQS_DP<7>")
	)
	(arc
		(start 92.091764 -229.597204)
		(mid 91.90781 -229.647333)
		(end 91.722956 -229.600506)
		(width 0.088646)
		(layer "In4.Cu")
		(net "M_C_CPU1_SB_DQS_DP<7>")
	)
	(arc
		(start 90.771472 -229.593648)
		(mid 90.491337 -229.521365)
		(end 90.212164 -229.597204)
		(width 0.088646)
		(layer "In4.Cu")
		(net "M_C_CPU1_SB_DQS_DP<7>")
	)
	(arc
		(start 92.657168 -229.597204)
		(mid 92.382969 -229.521369)
		(end 92.106496 -229.588568)
		(width 0.088646)
		(layer "In4.Cu")
		(net "M_C_CPU1_SB_DQS_DP<7>")
	)
	(arc
		(start 93.031564 -229.597204)
		(mid 92.844366 -229.647347)
		(end 92.657168 -229.597204)
		(width 0.088646)
		(layer "In4.Cu")
		(net "M_C_CPU1_SB_DQS_DP<7>")
	)
	(arc
		(start 89.272364 -229.597204)
		(mid 89.08841 -229.647333)
		(end 88.903556 -229.600506)
		(width 0.088646)
		(layer "In4.Cu")
		(net "M_C_CPU1_SB_DQS_DP<7>")
	)
	(arc
		(start 87.958168 -229.597204)
		(mid 87.683969 -229.521369)
		(end 87.407496 -229.588568)
		(width 0.088646)
		(layer "In4.Cu")
		(net "M_C_CPU1_SB_DQS_DP<7>")
	)
	(arc
		(start 89.831672 -229.593648)
		(mid 89.551537 -229.521365)
		(end 89.272364 -229.597204)
		(width 0.088646)
		(layer "In4.Cu")
		(net "M_C_CPU1_SB_DQS_DP<7>")
	)
	(segment
		(start 28.063952 -217.977974)
		(end 28.398216 -217.977974)
		(width 0.20066)
		(layer "F.Cu")
		(net "M_C_CPU1_SB_DQS_DP<6>")
	)
	(segment
		(start 27.328114 -217.716608)
		(end 27.802586 -217.716608)
		(width 0.20066)
		(layer "F.Cu")
		(net "M_C_CPU1_SB_DQS_DP<6>")
	)
	(segment
		(start 35.976814 -217.716608)
		(end 34.871914 -217.716608)
		(width 0.20066)
		(layer "F.Cu")
		(net "M_C_CPU1_SB_DQS_DP<6>")
	)
	(segment
		(start 34.382202 -217.716608)
		(end 34.871914 -217.716608)
		(width 0.20066)
		(layer "F.Cu")
		(net "M_C_CPU1_SB_DQS_DP<6>")
	)
	(segment
		(start 29.647642 -217.286078)
		(end 29.65323 -217.291666)
		(width 0.101854)
		(layer "F.Cu")
		(net "M_C_CPU1_SB_DQS_DP<6>")
	)
	(segment
		(start 31.972758 -217.29192)
		(end 32.114236 -217.29192)
		(width 0.20066)
		(layer "F.Cu")
		(net "M_C_CPU1_SB_DQS_DP<6>")
	)
	(segment
		(start 31.972504 -217.291666)
		(end 31.972758 -217.29192)
		(width 0.1016)
		(layer "F.Cu")
		(net "M_C_CPU1_SB_DQS_DP<6>")
	)
	(segment
		(start 32.114236 -217.29192)
		(end 32.375348 -217.553032)
		(width 0.20066)
		(layer "F.Cu")
		(net "M_C_CPU1_SB_DQS_DP<6>")
	)
	(segment
		(start 97.543366 -237.9472)
		(end 97.543366 -237.411514)
		(width 0.20066)
		(layer "F.Cu")
		(net "M_C_CPU1_SB_DQS_DP<6>")
	)
	(segment
		(start 97.543112 -237.947454)
		(end 97.543366 -237.9472)
		(width 0.20066)
		(layer "F.Cu")
		(net "M_C_CPU1_SB_DQS_DP<6>")
	)
	(segment
		(start 29.18079 -217.555572)
		(end 29.450284 -217.286078)
		(width 0.20066)
		(layer "F.Cu")
		(net "M_C_CPU1_SB_DQS_DP<6>")
	)
	(segment
		(start 28.820618 -217.555572)
		(end 29.18079 -217.555572)
		(width 0.20066)
		(layer "F.Cu")
		(net "M_C_CPU1_SB_DQS_DP<6>")
	)
	(segment
		(start 32.375348 -217.553032)
		(end 32.8803 -217.553032)
		(width 0.20066)
		(layer "F.Cu")
		(net "M_C_CPU1_SB_DQS_DP<6>")
	)
	(segment
		(start 27.802586 -217.716608)
		(end 28.063952 -217.977974)
		(width 0.20066)
		(layer "F.Cu")
		(net "M_C_CPU1_SB_DQS_DP<6>")
	)
	(segment
		(start 29.450284 -217.286078)
		(end 29.647642 -217.286078)
		(width 0.20066)
		(layer "F.Cu")
		(net "M_C_CPU1_SB_DQS_DP<6>")
	)
	(segment
		(start 29.89453 -217.291666)
		(end 31.972504 -217.291666)
		(width 0.1016)
		(layer "F.Cu")
		(net "M_C_CPU1_SB_DQS_DP<6>")
	)
	(segment
		(start 32.8803 -217.553032)
		(end 33.516316 -217.977974)
		(width 0.20066)
		(layer "F.Cu")
		(net "M_C_CPU1_SB_DQS_DP<6>")
	)
	(segment
		(start 34.120836 -217.977974)
		(end 34.382202 -217.716608)
		(width 0.20066)
		(layer "F.Cu")
		(net "M_C_CPU1_SB_DQS_DP<6>")
	)
	(segment
		(start 29.65323 -217.291666)
		(end 29.89453 -217.291666)
		(width 0.101854)
		(layer "F.Cu")
		(net "M_C_CPU1_SB_DQS_DP<6>")
	)
	(segment
		(start 33.516316 -217.977974)
		(end 34.120836 -217.977974)
		(width 0.20066)
		(layer "F.Cu")
		(net "M_C_CPU1_SB_DQS_DP<6>")
	)
	(segment
		(start 28.398216 -217.977974)
		(end 28.820618 -217.555572)
		(width 0.20066)
		(layer "F.Cu")
		(net "M_C_CPU1_SB_DQS_DP<6>")
	)
	(segment
		(start 36.674044 -217.99931)
		(end 36.259516 -217.99931)
		(width 0.18288)
		(layer "In6.Cu")
		(net "M_C_CPU1_SB_DQS_DP<6>")
	)
	(segment
		(start 83.329272 -234.667552)
		(end 83.114388 -234.452668)
		(width 0.088646)
		(layer "In6.Cu")
		(net "M_C_CPU1_SB_DQS_DP<6>")
	)
	(segment
		(start 94.066868 -236.922056)
		(end 94.056454 -236.91596)
		(width 0.088646)
		(layer "In6.Cu")
		(net "M_C_CPU1_SB_DQS_DP<6>")
	)
	(segment
		(start 50.092864 -220.938598)
		(end 49.256188 -220.101922)
		(width 0.18288)
		(layer "In6.Cu")
		(net "M_C_CPU1_SB_DQS_DP<6>")
	)
	(segment
		(start 47.20463 -219.841826)
		(end 46.70298 -219.841826)
		(width 0.18288)
		(layer "In6.Cu")
		(net "M_C_CPU1_SB_DQS_DP<6>")
	)
	(segment
		(start 82.858864 -234.392724)
		(end 82.835496 -234.392724)
		(width 0.088646)
		(layer "In6.Cu")
		(net "M_C_CPU1_SB_DQS_DP<6>")
	)
	(segment
		(start 82.918808 -234.452668)
		(end 82.858864 -234.392724)
		(width 0.088646)
		(layer "In6.Cu")
		(net "M_C_CPU1_SB_DQS_DP<6>")
	)
	(segment
		(start 84.040726 -235.57738)
		(end 83.329272 -234.865926)
		(width 0.088646)
		(layer "In6.Cu")
		(net "M_C_CPU1_SB_DQS_DP<6>")
	)
	(segment
		(start 62.94882 -221.544642)
		(end 62.147196 -221.21241)
		(width 0.18288)
		(layer "In6.Cu")
		(net "M_C_CPU1_SB_DQS_DP<6>")
	)
	(segment
		(start 89.367614 -236.922056)
		(end 89.3572 -236.91596)
		(width 0.088646)
		(layer "In6.Cu")
		(net "M_C_CPU1_SB_DQS_DP<6>")
	)
	(segment
		(start 66.628518 -224.396046)
		(end 66.323464 -224.090992)
		(width 0.18288)
		(layer "In6.Cu")
		(net "M_C_CPU1_SB_DQS_DP<6>")
	)
	(segment
		(start 36.259516 -217.99931)
		(end 35.976814 -217.716608)
		(width 0.18288)
		(layer "In6.Cu")
		(net "M_C_CPU1_SB_DQS_DP<6>")
	)
	(segment
		(start 68.52031 -228.00056)
		(end 68.52031 -225.830892)
		(width 0.18288)
		(layer "In6.Cu")
		(net "M_C_CPU1_SB_DQS_DP<6>")
	)
	(segment
		(start 49.256188 -220.101922)
		(end 47.464726 -220.101922)
		(width 0.18288)
		(layer "In6.Cu")
		(net "M_C_CPU1_SB_DQS_DP<6>")
	)
	(segment
		(start 54.959758 -220.94444)
		(end 51.574954 -220.94444)
		(width 0.18288)
		(layer "In6.Cu")
		(net "M_C_CPU1_SB_DQS_DP<6>")
	)
	(segment
		(start 65.68821 -224.37598)
		(end 64.898524 -224.37598)
		(width 0.18288)
		(layer "In6.Cu")
		(net "M_C_CPU1_SB_DQS_DP<6>")
	)
	(segment
		(start 97.230438 -237.411514)
		(end 97.164906 -237.345982)
		(width 0.088646)
		(layer "In6.Cu")
		(net "M_C_CPU1_SB_DQS_DP<6>")
	)
	(segment
		(start 84.260436 -236.159294)
		(end 84.040726 -235.939584)
		(width 0.088646)
		(layer "In6.Cu")
		(net "M_C_CPU1_SB_DQS_DP<6>")
	)
	(segment
		(start 96.89211 -236.925612)
		(end 96.886014 -236.922056)
		(width 0.088646)
		(layer "In6.Cu")
		(net "M_C_CPU1_SB_DQS_DP<6>")
	)
	(segment
		(start 59.753246 -221.21241)
		(end 58.789062 -220.248226)
		(width 0.18288)
		(layer "In6.Cu")
		(net "M_C_CPU1_SB_DQS_DP<6>")
	)
	(segment
		(start 55.655972 -220.248226)
		(end 54.959758 -220.94444)
		(width 0.18288)
		(layer "In6.Cu")
		(net "M_C_CPU1_SB_DQS_DP<6>")
	)
	(segment
		(start 91.247214 -236.922056)
		(end 91.232482 -236.91342)
		(width 0.088646)
		(layer "In6.Cu")
		(net "M_C_CPU1_SB_DQS_DP<6>")
	)
	(segment
		(start 45.903896 -220.09608)
		(end 45.212254 -219.404438)
		(width 0.18288)
		(layer "In6.Cu")
		(net "M_C_CPU1_SB_DQS_DP<6>")
	)
	(segment
		(start 40.740838 -218.64574)
		(end 39.73703 -218.229434)
		(width 0.18288)
		(layer "In6.Cu")
		(net "M_C_CPU1_SB_DQS_DP<6>")
	)
	(segment
		(start 44.42587 -219.404438)
		(end 43.815508 -220.0148)
		(width 0.18288)
		(layer "In6.Cu")
		(net "M_C_CPU1_SB_DQS_DP<6>")
	)
	(segment
		(start 50.558954 -220.938598)
		(end 50.092864 -220.938598)
		(width 0.18288)
		(layer "In6.Cu")
		(net "M_C_CPU1_SB_DQS_DP<6>")
	)
	(segment
		(start 67.083686 -224.396046)
		(end 66.628518 -224.396046)
		(width 0.18288)
		(layer "In6.Cu")
		(net "M_C_CPU1_SB_DQS_DP<6>")
	)
	(segment
		(start 86.937596 -236.913674)
		(end 86.922864 -236.92231)
		(width 0.088646)
		(layer "In6.Cu")
		(net "M_C_CPU1_SB_DQS_DP<6>")
	)
	(segment
		(start 63.573406 -223.050862)
		(end 62.94882 -221.544642)
		(width 0.18288)
		(layer "In6.Cu")
		(net "M_C_CPU1_SB_DQS_DP<6>")
	)
	(segment
		(start 90.307414 -236.922056)
		(end 90.292682 -236.91342)
		(width 0.088646)
		(layer "In6.Cu")
		(net "M_C_CPU1_SB_DQS_DP<6>")
	)
	(segment
		(start 51.321716 -220.691202)
		(end 50.80635 -220.691202)
		(width 0.18288)
		(layer "In6.Cu")
		(net "M_C_CPU1_SB_DQS_DP<6>")
	)
	(segment
		(start 39.73703 -218.229434)
		(end 36.904168 -218.229434)
		(width 0.18288)
		(layer "In6.Cu")
		(net "M_C_CPU1_SB_DQS_DP<6>")
	)
	(segment
		(start 43.111674 -220.0148)
		(end 41.742614 -218.64574)
		(width 0.18288)
		(layer "In6.Cu")
		(net "M_C_CPU1_SB_DQS_DP<6>")
	)
	(segment
		(start 65.973198 -224.090992)
		(end 65.68821 -224.37598)
		(width 0.18288)
		(layer "In6.Cu")
		(net "M_C_CPU1_SB_DQS_DP<6>")
	)
	(segment
		(start 68.52031 -225.830892)
		(end 67.083686 -224.396046)
		(width 0.18288)
		(layer "In6.Cu")
		(net "M_C_CPU1_SB_DQS_DP<6>")
	)
	(segment
		(start 41.742614 -218.64574)
		(end 40.740838 -218.64574)
		(width 0.18288)
		(layer "In6.Cu")
		(net "M_C_CPU1_SB_DQS_DP<6>")
	)
	(segment
		(start 58.789062 -220.248226)
		(end 55.655972 -220.248226)
		(width 0.18288)
		(layer "In6.Cu")
		(net "M_C_CPU1_SB_DQS_DP<6>")
	)
	(segment
		(start 85.52815 -236.099858)
		(end 85.513418 -236.108494)
		(width 0.088646)
		(layer "In6.Cu")
		(net "M_C_CPU1_SB_DQS_DP<6>")
	)
	(segment
		(start 62.147196 -221.21241)
		(end 59.753246 -221.21241)
		(width 0.18288)
		(layer "In6.Cu")
		(net "M_C_CPU1_SB_DQS_DP<6>")
	)
	(segment
		(start 66.323464 -224.090992)
		(end 65.973198 -224.090992)
		(width 0.18288)
		(layer "In6.Cu")
		(net "M_C_CPU1_SB_DQS_DP<6>")
	)
	(segment
		(start 97.543366 -237.411514)
		(end 97.230438 -237.411514)
		(width 0.088646)
		(layer "In6.Cu")
		(net "M_C_CPU1_SB_DQS_DP<6>")
	)
	(segment
		(start 82.835496 -234.392724)
		(end 74.912474 -234.392724)
		(width 0.18288)
		(layer "In6.Cu")
		(net "M_C_CPU1_SB_DQS_DP<6>")
	)
	(segment
		(start 50.80635 -220.691202)
		(end 50.558954 -220.938598)
		(width 0.18288)
		(layer "In6.Cu")
		(net "M_C_CPU1_SB_DQS_DP<6>")
	)
	(segment
		(start 64.898524 -224.37598)
		(end 63.573406 -223.050862)
		(width 0.18288)
		(layer "In6.Cu")
		(net "M_C_CPU1_SB_DQS_DP<6>")
	)
	(segment
		(start 83.114388 -234.452668)
		(end 82.918808 -234.452668)
		(width 0.088646)
		(layer "In6.Cu")
		(net "M_C_CPU1_SB_DQS_DP<6>")
	)
	(segment
		(start 47.464726 -220.101922)
		(end 47.20463 -219.841826)
		(width 0.18288)
		(layer "In6.Cu")
		(net "M_C_CPU1_SB_DQS_DP<6>")
	)
	(segment
		(start 46.448726 -220.09608)
		(end 45.903896 -220.09608)
		(width 0.18288)
		(layer "In6.Cu")
		(net "M_C_CPU1_SB_DQS_DP<6>")
	)
	(segment
		(start 74.912474 -234.392724)
		(end 68.52031 -228.00056)
		(width 0.18288)
		(layer "In6.Cu")
		(net "M_C_CPU1_SB_DQS_DP<6>")
	)
	(segment
		(start 95.006414 -236.922056)
		(end 94.996 -236.91596)
		(width 0.088646)
		(layer "In6.Cu")
		(net "M_C_CPU1_SB_DQS_DP<6>")
	)
	(segment
		(start 45.212254 -219.404438)
		(end 44.42587 -219.404438)
		(width 0.18288)
		(layer "In6.Cu")
		(net "M_C_CPU1_SB_DQS_DP<6>")
	)
	(segment
		(start 43.815508 -220.0148)
		(end 43.111674 -220.0148)
		(width 0.18288)
		(layer "In6.Cu")
		(net "M_C_CPU1_SB_DQS_DP<6>")
	)
	(segment
		(start 36.904168 -218.229434)
		(end 36.674044 -217.99931)
		(width 0.18288)
		(layer "In6.Cu")
		(net "M_C_CPU1_SB_DQS_DP<6>")
	)
	(segment
		(start 93.126814 -236.922056)
		(end 93.112082 -236.91342)
		(width 0.088646)
		(layer "In6.Cu")
		(net "M_C_CPU1_SB_DQS_DP<6>")
	)
	(segment
		(start 86.361016 -236.597952)
		(end 86.361016 -236.588046)
		(width 0.088646)
		(layer "In6.Cu")
		(net "M_C_CPU1_SB_DQS_DP<6>")
	)
	(segment
		(start 84.385912 -236.159294)
		(end 84.260436 -236.159294)
		(width 0.088646)
		(layer "In6.Cu")
		(net "M_C_CPU1_SB_DQS_DP<6>")
	)
	(segment
		(start 95.946214 -236.922056)
		(end 95.931482 -236.91342)
		(width 0.088646)
		(layer "In6.Cu")
		(net "M_C_CPU1_SB_DQS_DP<6>")
	)
	(segment
		(start 84.040726 -235.939584)
		(end 84.040726 -235.57738)
		(width 0.088646)
		(layer "In6.Cu")
		(net "M_C_CPU1_SB_DQS_DP<6>")
	)
	(segment
		(start 51.574954 -220.94444)
		(end 51.321716 -220.691202)
		(width 0.18288)
		(layer "In6.Cu")
		(net "M_C_CPU1_SB_DQS_DP<6>")
	)
	(segment
		(start 46.70298 -219.841826)
		(end 46.448726 -220.09608)
		(width 0.18288)
		(layer "In6.Cu")
		(net "M_C_CPU1_SB_DQS_DP<6>")
	)
	(segment
		(start 87.862664 -236.922056)
		(end 87.851742 -236.928406)
		(width 0.088646)
		(layer "In6.Cu")
		(net "M_C_CPU1_SB_DQS_DP<6>")
	)
	(segment
		(start 83.329272 -234.865926)
		(end 83.329272 -234.667552)
		(width 0.088646)
		(layer "In6.Cu")
		(net "M_C_CPU1_SB_DQS_DP<6>")
	)
	(segment
		(start 96.886014 -236.922056)
		(end 96.871282 -236.91342)
		(width 0.088646)
		(layer "In6.Cu")
		(net "M_C_CPU1_SB_DQS_DP<6>")
	)
	(arc
		(start 86.922864 -236.92231)
		(mid 86.548389 -236.922264)
		(end 86.361016 -236.597952)
		(width 0.088646)
		(layer "In6.Cu")
		(net "M_C_CPU1_SB_DQS_DP<6>")
	)
	(arc
		(start 87.851742 -236.928406)
		(mid 87.669212 -236.97243)
		(end 87.488268 -236.92231)
		(width 0.088646)
		(layer "In6.Cu")
		(net "M_C_CPU1_SB_DQS_DP<6>")
	)
	(arc
		(start 87.488268 -236.92231)
		(mid 87.214069 -236.846475)
		(end 86.937596 -236.913674)
		(width 0.088646)
		(layer "In6.Cu")
		(net "M_C_CPU1_SB_DQS_DP<6>")
	)
	(arc
		(start 96.32061 -236.922056)
		(mid 96.133412 -236.972233)
		(end 95.946214 -236.922056)
		(width 0.088646)
		(layer "In6.Cu")
		(net "M_C_CPU1_SB_DQS_DP<6>")
	)
	(arc
		(start 85.513418 -236.108494)
		(mid 85.32622 -236.158637)
		(end 85.139022 -236.108494)
		(width 0.088646)
		(layer "In6.Cu")
		(net "M_C_CPU1_SB_DQS_DP<6>")
	)
	(arc
		(start 96.871282 -236.91342)
		(mid 96.594807 -236.8461)
		(end 96.32061 -236.922056)
		(width 0.088646)
		(layer "In6.Cu")
		(net "M_C_CPU1_SB_DQS_DP<6>")
	)
	(arc
		(start 84.57311 -236.108494)
		(mid 84.482854 -236.146216)
		(end 84.385912 -236.159294)
		(width 0.088646)
		(layer "In6.Cu")
		(net "M_C_CPU1_SB_DQS_DP<6>")
	)
	(arc
		(start 90.68181 -236.922056)
		(mid 90.494612 -236.972233)
		(end 90.307414 -236.922056)
		(width 0.088646)
		(layer "In6.Cu")
		(net "M_C_CPU1_SB_DQS_DP<6>")
	)
	(arc
		(start 85.139022 -236.108494)
		(mid 84.856066 -236.032591)
		(end 84.57311 -236.108494)
		(width 0.088646)
		(layer "In6.Cu")
		(net "M_C_CPU1_SB_DQS_DP<6>")
	)
	(arc
		(start 91.62161 -236.922056)
		(mid 91.434412 -236.972233)
		(end 91.247214 -236.922056)
		(width 0.088646)
		(layer "In6.Cu")
		(net "M_C_CPU1_SB_DQS_DP<6>")
	)
	(arc
		(start 93.50121 -236.922056)
		(mid 93.314012 -236.972233)
		(end 93.126814 -236.922056)
		(width 0.088646)
		(layer "In6.Cu")
		(net "M_C_CPU1_SB_DQS_DP<6>")
	)
	(arc
		(start 97.164906 -237.345982)
		(mid 97.077662 -237.103894)
		(end 96.89211 -236.925612)
		(width 0.088646)
		(layer "In6.Cu")
		(net "M_C_CPU1_SB_DQS_DP<6>")
	)
	(arc
		(start 92.56141 -236.922056)
		(mid 92.374212 -236.972233)
		(end 92.187014 -236.922056)
		(width 0.088646)
		(layer "In6.Cu")
		(net "M_C_CPU1_SB_DQS_DP<6>")
	)
	(arc
		(start 90.292682 -236.91342)
		(mid 90.016207 -236.8461)
		(end 89.74201 -236.922056)
		(width 0.088646)
		(layer "In6.Cu")
		(net "M_C_CPU1_SB_DQS_DP<6>")
	)
	(arc
		(start 92.187014 -236.922056)
		(mid 91.904312 -236.84628)
		(end 91.62161 -236.922056)
		(width 0.088646)
		(layer "In6.Cu")
		(net "M_C_CPU1_SB_DQS_DP<6>")
	)
	(arc
		(start 89.74201 -236.922056)
		(mid 89.554812 -236.972233)
		(end 89.367614 -236.922056)
		(width 0.088646)
		(layer "In6.Cu")
		(net "M_C_CPU1_SB_DQS_DP<6>")
	)
	(arc
		(start 95.38081 -236.922056)
		(mid 95.193612 -236.972233)
		(end 95.006414 -236.922056)
		(width 0.088646)
		(layer "In6.Cu")
		(net "M_C_CPU1_SB_DQS_DP<6>")
	)
	(arc
		(start 88.428068 -236.922056)
		(mid 88.145366 -236.84628)
		(end 87.862664 -236.922056)
		(width 0.088646)
		(layer "In6.Cu")
		(net "M_C_CPU1_SB_DQS_DP<6>")
	)
	(arc
		(start 88.802464 -236.922056)
		(mid 88.615266 -236.972233)
		(end 88.428068 -236.922056)
		(width 0.088646)
		(layer "In6.Cu")
		(net "M_C_CPU1_SB_DQS_DP<6>")
	)
	(arc
		(start 94.441264 -236.922056)
		(mid 94.254066 -236.972233)
		(end 94.066868 -236.922056)
		(width 0.088646)
		(layer "In6.Cu")
		(net "M_C_CPU1_SB_DQS_DP<6>")
	)
	(arc
		(start 93.112082 -236.91342)
		(mid 92.835607 -236.8461)
		(end 92.56141 -236.922056)
		(width 0.088646)
		(layer "In6.Cu")
		(net "M_C_CPU1_SB_DQS_DP<6>")
	)
	(arc
		(start 91.232482 -236.91342)
		(mid 90.956007 -236.8461)
		(end 90.68181 -236.922056)
		(width 0.088646)
		(layer "In6.Cu")
		(net "M_C_CPU1_SB_DQS_DP<6>")
	)
	(arc
		(start 86.361016 -236.588046)
		(mid 86.081689 -236.110058)
		(end 85.52815 -236.099858)
		(width 0.088646)
		(layer "In6.Cu")
		(net "M_C_CPU1_SB_DQS_DP<6>")
	)
	(arc
		(start 94.056454 -236.91596)
		(mid 93.778022 -236.846114)
		(end 93.50121 -236.922056)
		(width 0.088646)
		(layer "In6.Cu")
		(net "M_C_CPU1_SB_DQS_DP<6>")
	)
	(arc
		(start 89.3572 -236.91596)
		(mid 89.079022 -236.846237)
		(end 88.802464 -236.922056)
		(width 0.088646)
		(layer "In6.Cu")
		(net "M_C_CPU1_SB_DQS_DP<6>")
	)
	(arc
		(start 95.931482 -236.91342)
		(mid 95.655007 -236.8461)
		(end 95.38081 -236.922056)
		(width 0.088646)
		(layer "In6.Cu")
		(net "M_C_CPU1_SB_DQS_DP<6>")
	)
	(arc
		(start 94.996 -236.91596)
		(mid 94.717822 -236.846237)
		(end 94.441264 -236.922056)
		(width 0.088646)
		(layer "In6.Cu")
		(net "M_C_CPU1_SB_DQS_DP<6>")
	)
	(segment
		(start 28.398216 -227.327968)
		(end 28.820618 -226.905566)
		(width 0.20066)
		(layer "F.Cu")
		(net "M_C_CPU1_SB_DQS_DP<5>")
	)
	(segment
		(start 34.120836 -227.327968)
		(end 34.382202 -227.066602)
		(width 0.20066)
		(layer "F.Cu")
		(net "M_C_CPU1_SB_DQS_DP<5>")
	)
	(segment
		(start 31.972758 -226.641914)
		(end 32.114236 -226.641914)
		(width 0.20066)
		(layer "F.Cu")
		(net "M_C_CPU1_SB_DQS_DP<5>")
	)
	(segment
		(start 29.65323 -226.64166)
		(end 29.89453 -226.64166)
		(width 0.101854)
		(layer "F.Cu")
		(net "M_C_CPU1_SB_DQS_DP<5>")
	)
	(segment
		(start 32.114236 -226.641914)
		(end 32.375348 -226.903026)
		(width 0.20066)
		(layer "F.Cu")
		(net "M_C_CPU1_SB_DQS_DP<5>")
	)
	(segment
		(start 35.976814 -227.066602)
		(end 34.871914 -227.066602)
		(width 0.20066)
		(layer "F.Cu")
		(net "M_C_CPU1_SB_DQS_DP<5>")
	)
	(segment
		(start 29.647642 -226.636072)
		(end 29.65323 -226.64166)
		(width 0.101854)
		(layer "F.Cu")
		(net "M_C_CPU1_SB_DQS_DP<5>")
	)
	(segment
		(start 33.516316 -227.327968)
		(end 34.120836 -227.327968)
		(width 0.20066)
		(layer "F.Cu")
		(net "M_C_CPU1_SB_DQS_DP<5>")
	)
	(segment
		(start 28.820618 -226.905566)
		(end 29.18079 -226.905566)
		(width 0.20066)
		(layer "F.Cu")
		(net "M_C_CPU1_SB_DQS_DP<5>")
	)
	(segment
		(start 27.802586 -227.066602)
		(end 28.063952 -227.327968)
		(width 0.20066)
		(layer "F.Cu")
		(net "M_C_CPU1_SB_DQS_DP<5>")
	)
	(segment
		(start 31.972504 -226.64166)
		(end 31.972758 -226.641914)
		(width 0.1016)
		(layer "F.Cu")
		(net "M_C_CPU1_SB_DQS_DP<5>")
	)
	(segment
		(start 29.450284 -226.636072)
		(end 29.647642 -226.636072)
		(width 0.20066)
		(layer "F.Cu")
		(net "M_C_CPU1_SB_DQS_DP<5>")
	)
	(segment
		(start 29.18079 -226.905566)
		(end 29.450284 -226.636072)
		(width 0.20066)
		(layer "F.Cu")
		(net "M_C_CPU1_SB_DQS_DP<5>")
	)
	(segment
		(start 97.543112 -242.830858)
		(end 97.543366 -242.294918)
		(width 0.20066)
		(layer "F.Cu")
		(net "M_C_CPU1_SB_DQS_DP<5>")
	)
	(segment
		(start 28.063952 -227.327968)
		(end 28.398216 -227.327968)
		(width 0.20066)
		(layer "F.Cu")
		(net "M_C_CPU1_SB_DQS_DP<5>")
	)
	(segment
		(start 34.382202 -227.066602)
		(end 34.871914 -227.066602)
		(width 0.20066)
		(layer "F.Cu")
		(net "M_C_CPU1_SB_DQS_DP<5>")
	)
	(segment
		(start 27.328114 -227.066602)
		(end 27.802586 -227.066602)
		(width 0.20066)
		(layer "F.Cu")
		(net "M_C_CPU1_SB_DQS_DP<5>")
	)
	(segment
		(start 32.8803 -226.903026)
		(end 33.516316 -227.327968)
		(width 0.20066)
		(layer "F.Cu")
		(net "M_C_CPU1_SB_DQS_DP<5>")
	)
	(segment
		(start 32.375348 -226.903026)
		(end 32.8803 -226.903026)
		(width 0.20066)
		(layer "F.Cu")
		(net "M_C_CPU1_SB_DQS_DP<5>")
	)
	(segment
		(start 29.89453 -226.64166)
		(end 31.972504 -226.64166)
		(width 0.1016)
		(layer "F.Cu")
		(net "M_C_CPU1_SB_DQS_DP<5>")
	)
	(segment
		(start 86.937596 -241.796824)
		(end 86.922864 -241.80546)
		(width 0.088646)
		(layer "In6.Cu")
		(net "M_C_CPU1_SB_DQS_DP<5>")
	)
	(segment
		(start 46.741334 -230.891842)
		(end 46.486826 -231.14635)
		(width 0.18288)
		(layer "In6.Cu")
		(net "M_C_CPU1_SB_DQS_DP<5>")
	)
	(segment
		(start 45.953934 -231.14635)
		(end 45.18787 -230.380286)
		(width 0.18288)
		(layer "In6.Cu")
		(net "M_C_CPU1_SB_DQS_DP<5>")
	)
	(segment
		(start 47.242476 -230.891842)
		(end 46.741334 -230.891842)
		(width 0.18288)
		(layer "In6.Cu")
		(net "M_C_CPU1_SB_DQS_DP<5>")
	)
	(segment
		(start 44.62399 -230.380286)
		(end 43.94327 -229.699566)
		(width 0.18288)
		(layer "In6.Cu")
		(net "M_C_CPU1_SB_DQS_DP<5>")
	)
	(segment
		(start 46.486826 -231.14635)
		(end 45.953934 -231.14635)
		(width 0.18288)
		(layer "In6.Cu")
		(net "M_C_CPU1_SB_DQS_DP<5>")
	)
	(segment
		(start 96.89211 -241.809016)
		(end 96.886014 -241.80546)
		(width 0.088646)
		(layer "In6.Cu")
		(net "M_C_CPU1_SB_DQS_DP<5>")
	)
	(segment
		(start 50.586894 -231.996234)
		(end 50.063654 -231.996234)
		(width 0.18288)
		(layer "In6.Cu")
		(net "M_C_CPU1_SB_DQS_DP<5>")
	)
	(segment
		(start 85.622384 -241.813842)
		(end 85.584538 -241.791998)
		(width 0.088646)
		(layer "In6.Cu")
		(net "M_C_CPU1_SB_DQS_DP<5>")
	)
	(segment
		(start 71.790306 -240.308384)
		(end 67.503548 -236.021626)
		(width 0.18288)
		(layer "In6.Cu")
		(net "M_C_CPU1_SB_DQS_DP<5>")
	)
	(segment
		(start 84.616798 -241.606324)
		(end 84.496402 -241.485928)
		(width 0.088646)
		(layer "In6.Cu")
		(net "M_C_CPU1_SB_DQS_DP<5>")
	)
	(segment
		(start 64.59855 -234.782106)
		(end 63.998094 -234.782106)
		(width 0.18288)
		(layer "In6.Cu")
		(net "M_C_CPU1_SB_DQS_DP<5>")
	)
	(segment
		(start 40.16502 -228.66858)
		(end 39.111936 -228.66858)
		(width 0.18288)
		(layer "In6.Cu")
		(net "M_C_CPU1_SB_DQS_DP<5>")
	)
	(segment
		(start 47.502826 -231.152192)
		(end 47.242476 -230.891842)
		(width 0.18288)
		(layer "In6.Cu")
		(net "M_C_CPU1_SB_DQS_DP<5>")
	)
	(segment
		(start 83.482434 -240.368328)
		(end 83.172808 -240.368328)
		(width 0.088646)
		(layer "In6.Cu")
		(net "M_C_CPU1_SB_DQS_DP<5>")
	)
	(segment
		(start 50.063654 -231.996234)
		(end 49.47793 -231.41051)
		(width 0.18288)
		(layer "In6.Cu")
		(net "M_C_CPU1_SB_DQS_DP<5>")
	)
	(segment
		(start 83.089496 -240.308384)
		(end 71.790306 -240.308384)
		(width 0.18288)
		(layer "In6.Cu")
		(net "M_C_CPU1_SB_DQS_DP<5>")
	)
	(segment
		(start 55.130954 -232.024428)
		(end 51.625246 -232.024428)
		(width 0.18288)
		(layer "In6.Cu")
		(net "M_C_CPU1_SB_DQS_DP<5>")
	)
	(segment
		(start 84.284058 -241.169952)
		(end 83.482434 -240.368328)
		(width 0.088646)
		(layer "In6.Cu")
		(net "M_C_CPU1_SB_DQS_DP<5>")
	)
	(segment
		(start 62.854332 -233.638344)
		(end 59.637676 -233.638344)
		(width 0.18288)
		(layer "In6.Cu")
		(net "M_C_CPU1_SB_DQS_DP<5>")
	)
	(segment
		(start 48.415194 -231.41051)
		(end 48.156876 -231.152192)
		(width 0.18288)
		(layer "In6.Cu")
		(net "M_C_CPU1_SB_DQS_DP<5>")
	)
	(segment
		(start 37.950902 -227.507546)
		(end 36.88334 -227.507546)
		(width 0.18288)
		(layer "In6.Cu")
		(net "M_C_CPU1_SB_DQS_DP<5>")
	)
	(segment
		(start 93.126814 -241.80546)
		(end 93.112082 -241.796824)
		(width 0.088646)
		(layer "In6.Cu")
		(net "M_C_CPU1_SB_DQS_DP<5>")
	)
	(segment
		(start 49.47793 -231.41051)
		(end 48.415194 -231.41051)
		(width 0.18288)
		(layer "In6.Cu")
		(net "M_C_CPU1_SB_DQS_DP<5>")
	)
	(segment
		(start 97.230438 -242.294918)
		(end 97.164906 -242.229386)
		(width 0.088646)
		(layer "In6.Cu")
		(net "M_C_CPU1_SB_DQS_DP<5>")
	)
	(segment
		(start 86.548468 -241.80546)
		(end 86.533736 -241.796824)
		(width 0.088646)
		(layer "In6.Cu")
		(net "M_C_CPU1_SB_DQS_DP<5>")
	)
	(segment
		(start 83.112864 -240.308384)
		(end 83.089496 -240.308384)
		(width 0.088646)
		(layer "In6.Cu")
		(net "M_C_CPU1_SB_DQS_DP<5>")
	)
	(segment
		(start 51.625246 -232.024428)
		(end 51.342544 -231.741726)
		(width 0.18288)
		(layer "In6.Cu")
		(net "M_C_CPU1_SB_DQS_DP<5>")
	)
	(segment
		(start 43.94327 -229.699566)
		(end 41.196006 -229.699566)
		(width 0.18288)
		(layer "In6.Cu")
		(net "M_C_CPU1_SB_DQS_DP<5>")
	)
	(segment
		(start 91.247214 -241.80546)
		(end 91.232482 -241.796824)
		(width 0.088646)
		(layer "In6.Cu")
		(net "M_C_CPU1_SB_DQS_DP<5>")
	)
	(segment
		(start 63.998094 -234.782106)
		(end 62.854332 -233.638344)
		(width 0.18288)
		(layer "In6.Cu")
		(net "M_C_CPU1_SB_DQS_DP<5>")
	)
	(segment
		(start 55.999126 -232.8926)
		(end 55.130954 -232.024428)
		(width 0.18288)
		(layer "In6.Cu")
		(net "M_C_CPU1_SB_DQS_DP<5>")
	)
	(segment
		(start 41.196006 -229.699566)
		(end 40.16502 -228.66858)
		(width 0.18288)
		(layer "In6.Cu")
		(net "M_C_CPU1_SB_DQS_DP<5>")
	)
	(segment
		(start 95.946214 -241.80546)
		(end 95.931482 -241.796824)
		(width 0.088646)
		(layer "In6.Cu")
		(net "M_C_CPU1_SB_DQS_DP<5>")
	)
	(segment
		(start 96.886014 -241.80546)
		(end 96.871282 -241.796824)
		(width 0.088646)
		(layer "In6.Cu")
		(net "M_C_CPU1_SB_DQS_DP<5>")
	)
	(segment
		(start 67.503548 -236.021626)
		(end 65.83807 -236.021626)
		(width 0.18288)
		(layer "In6.Cu")
		(net "M_C_CPU1_SB_DQS_DP<5>")
	)
	(segment
		(start 97.543366 -242.294918)
		(end 97.230438 -242.294918)
		(width 0.088646)
		(layer "In6.Cu")
		(net "M_C_CPU1_SB_DQS_DP<5>")
	)
	(segment
		(start 59.637676 -233.638344)
		(end 58.891932 -232.8926)
		(width 0.18288)
		(layer "In6.Cu")
		(net "M_C_CPU1_SB_DQS_DP<5>")
	)
	(segment
		(start 65.83807 -236.021626)
		(end 64.59855 -234.782106)
		(width 0.18288)
		(layer "In6.Cu")
		(net "M_C_CPU1_SB_DQS_DP<5>")
	)
	(segment
		(start 36.723828 -227.348034)
		(end 36.258246 -227.348034)
		(width 0.18288)
		(layer "In6.Cu")
		(net "M_C_CPU1_SB_DQS_DP<5>")
	)
	(segment
		(start 94.066868 -241.80546)
		(end 94.056454 -241.799364)
		(width 0.088646)
		(layer "In6.Cu")
		(net "M_C_CPU1_SB_DQS_DP<5>")
	)
	(segment
		(start 48.156876 -231.152192)
		(end 47.502826 -231.152192)
		(width 0.18288)
		(layer "In6.Cu")
		(net "M_C_CPU1_SB_DQS_DP<5>")
	)
	(segment
		(start 45.18787 -230.380286)
		(end 44.62399 -230.380286)
		(width 0.18288)
		(layer "In6.Cu")
		(net "M_C_CPU1_SB_DQS_DP<5>")
	)
	(segment
		(start 83.172808 -240.368328)
		(end 83.112864 -240.308384)
		(width 0.088646)
		(layer "In6.Cu")
		(net "M_C_CPU1_SB_DQS_DP<5>")
	)
	(segment
		(start 39.111936 -228.66858)
		(end 37.950902 -227.507546)
		(width 0.18288)
		(layer "In6.Cu")
		(net "M_C_CPU1_SB_DQS_DP<5>")
	)
	(segment
		(start 90.307414 -241.80546)
		(end 90.292682 -241.796824)
		(width 0.088646)
		(layer "In6.Cu")
		(net "M_C_CPU1_SB_DQS_DP<5>")
	)
	(segment
		(start 58.891932 -232.8926)
		(end 55.999126 -232.8926)
		(width 0.18288)
		(layer "In6.Cu")
		(net "M_C_CPU1_SB_DQS_DP<5>")
	)
	(segment
		(start 50.841402 -231.741726)
		(end 50.586894 -231.996234)
		(width 0.18288)
		(layer "In6.Cu")
		(net "M_C_CPU1_SB_DQS_DP<5>")
	)
	(segment
		(start 89.367614 -241.80546)
		(end 89.352882 -241.796824)
		(width 0.088646)
		(layer "In6.Cu")
		(net "M_C_CPU1_SB_DQS_DP<5>")
	)
	(segment
		(start 36.88334 -227.507546)
		(end 36.723828 -227.348034)
		(width 0.18288)
		(layer "In6.Cu")
		(net "M_C_CPU1_SB_DQS_DP<5>")
	)
	(segment
		(start 88.43645 -241.810286)
		(end 88.413336 -241.796824)
		(width 0.088646)
		(layer "In6.Cu")
		(net "M_C_CPU1_SB_DQS_DP<5>")
	)
	(segment
		(start 51.342544 -231.741726)
		(end 50.841402 -231.741726)
		(width 0.18288)
		(layer "In6.Cu")
		(net "M_C_CPU1_SB_DQS_DP<5>")
	)
	(segment
		(start 92.187014 -241.80546)
		(end 92.172282 -241.796824)
		(width 0.088646)
		(layer "In6.Cu")
		(net "M_C_CPU1_SB_DQS_DP<5>")
	)
	(segment
		(start 36.258246 -227.348034)
		(end 35.976814 -227.066602)
		(width 0.18288)
		(layer "In6.Cu")
		(net "M_C_CPU1_SB_DQS_DP<5>")
	)
	(segment
		(start 95.006414 -241.80546)
		(end 94.996 -241.799364)
		(width 0.088646)
		(layer "In6.Cu")
		(net "M_C_CPU1_SB_DQS_DP<5>")
	)
	(arc
		(start 95.38081 -241.80546)
		(mid 95.193612 -241.855603)
		(end 95.006414 -241.80546)
		(width 0.088646)
		(layer "In6.Cu")
		(net "M_C_CPU1_SB_DQS_DP<5>")
	)
	(arc
		(start 89.352882 -241.796824)
		(mid 89.076407 -241.729504)
		(end 88.80221 -241.80546)
		(width 0.088646)
		(layer "In6.Cu")
		(net "M_C_CPU1_SB_DQS_DP<5>")
	)
	(arc
		(start 84.496402 -241.485928)
		(mid 84.435592 -241.411987)
		(end 84.39023 -241.327686)
		(width 0.088646)
		(layer "In6.Cu")
		(net "M_C_CPU1_SB_DQS_DP<5>")
	)
	(arc
		(start 91.62161 -241.80546)
		(mid 91.434412 -241.855603)
		(end 91.247214 -241.80546)
		(width 0.088646)
		(layer "In6.Cu")
		(net "M_C_CPU1_SB_DQS_DP<5>")
	)
	(arc
		(start 94.056454 -241.799364)
		(mid 93.778022 -241.729518)
		(end 93.50121 -241.80546)
		(width 0.088646)
		(layer "In6.Cu")
		(net "M_C_CPU1_SB_DQS_DP<5>")
	)
	(arc
		(start 88.413336 -241.796824)
		(mid 88.136861 -241.729504)
		(end 87.862664 -241.80546)
		(width 0.088646)
		(layer "In6.Cu")
		(net "M_C_CPU1_SB_DQS_DP<5>")
	)
	(arc
		(start 92.56141 -241.80546)
		(mid 92.374212 -241.855603)
		(end 92.187014 -241.80546)
		(width 0.088646)
		(layer "In6.Cu")
		(net "M_C_CPU1_SB_DQS_DP<5>")
	)
	(arc
		(start 89.74201 -241.80546)
		(mid 89.554812 -241.855603)
		(end 89.367614 -241.80546)
		(width 0.088646)
		(layer "In6.Cu")
		(net "M_C_CPU1_SB_DQS_DP<5>")
	)
	(arc
		(start 94.996 -241.799364)
		(mid 94.717822 -241.729641)
		(end 94.441264 -241.80546)
		(width 0.088646)
		(layer "In6.Cu")
		(net "M_C_CPU1_SB_DQS_DP<5>")
	)
	(arc
		(start 96.32061 -241.80546)
		(mid 96.133412 -241.855603)
		(end 95.946214 -241.80546)
		(width 0.088646)
		(layer "In6.Cu")
		(net "M_C_CPU1_SB_DQS_DP<5>")
	)
	(arc
		(start 90.292682 -241.796824)
		(mid 90.016207 -241.729504)
		(end 89.74201 -241.80546)
		(width 0.088646)
		(layer "In6.Cu")
		(net "M_C_CPU1_SB_DQS_DP<5>")
	)
	(arc
		(start 96.871282 -241.796824)
		(mid 96.594807 -241.729504)
		(end 96.32061 -241.80546)
		(width 0.088646)
		(layer "In6.Cu")
		(net "M_C_CPU1_SB_DQS_DP<5>")
	)
	(arc
		(start 93.50121 -241.80546)
		(mid 93.314012 -241.855603)
		(end 93.126814 -241.80546)
		(width 0.088646)
		(layer "In6.Cu")
		(net "M_C_CPU1_SB_DQS_DP<5>")
	)
	(arc
		(start 92.172282 -241.796824)
		(mid 91.895807 -241.729504)
		(end 91.62161 -241.80546)
		(width 0.088646)
		(layer "In6.Cu")
		(net "M_C_CPU1_SB_DQS_DP<5>")
	)
	(arc
		(start 94.441264 -241.80546)
		(mid 94.254066 -241.855603)
		(end 94.066868 -241.80546)
		(width 0.088646)
		(layer "In6.Cu")
		(net "M_C_CPU1_SB_DQS_DP<5>")
	)
	(arc
		(start 90.68181 -241.80546)
		(mid 90.494612 -241.855603)
		(end 90.307414 -241.80546)
		(width 0.088646)
		(layer "In6.Cu")
		(net "M_C_CPU1_SB_DQS_DP<5>")
	)
	(arc
		(start 87.862664 -241.80546)
		(mid 87.675466 -241.855603)
		(end 87.488268 -241.80546)
		(width 0.088646)
		(layer "In6.Cu")
		(net "M_C_CPU1_SB_DQS_DP<5>")
	)
	(arc
		(start 86.533736 -241.796824)
		(mid 86.257007 -241.729384)
		(end 85.982556 -241.80546)
		(width 0.088646)
		(layer "In6.Cu")
		(net "M_C_CPU1_SB_DQS_DP<5>")
	)
	(arc
		(start 85.584538 -241.791998)
		(mid 85.381846 -241.732005)
		(end 85.17128 -241.750596)
		(width 0.088646)
		(layer "In6.Cu")
		(net "M_C_CPU1_SB_DQS_DP<5>")
	)
	(arc
		(start 88.80221 -241.80546)
		(mid 88.619959 -241.855571)
		(end 88.43645 -241.810286)
		(width 0.088646)
		(layer "In6.Cu")
		(net "M_C_CPU1_SB_DQS_DP<5>")
	)
	(arc
		(start 85.982556 -241.80546)
		(mid 85.803546 -241.855757)
		(end 85.622384 -241.813842)
		(width 0.088646)
		(layer "In6.Cu")
		(net "M_C_CPU1_SB_DQS_DP<5>")
	)
	(arc
		(start 91.232482 -241.796824)
		(mid 90.956007 -241.729504)
		(end 90.68181 -241.80546)
		(width 0.088646)
		(layer "In6.Cu")
		(net "M_C_CPU1_SB_DQS_DP<5>")
	)
	(arc
		(start 93.112082 -241.796824)
		(mid 92.835607 -241.729504)
		(end 92.56141 -241.80546)
		(width 0.088646)
		(layer "In6.Cu")
		(net "M_C_CPU1_SB_DQS_DP<5>")
	)
	(arc
		(start 86.922864 -241.80546)
		(mid 86.735666 -241.855603)
		(end 86.548468 -241.80546)
		(width 0.088646)
		(layer "In6.Cu")
		(net "M_C_CPU1_SB_DQS_DP<5>")
	)
	(arc
		(start 87.488268 -241.80546)
		(mid 87.214069 -241.729625)
		(end 86.937596 -241.796824)
		(width 0.088646)
		(layer "In6.Cu")
		(net "M_C_CPU1_SB_DQS_DP<5>")
	)
	(arc
		(start 84.39023 -241.327686)
		(mid 84.344823 -241.243649)
		(end 84.284058 -241.169952)
		(width 0.088646)
		(layer "In6.Cu")
		(net "M_C_CPU1_SB_DQS_DP<5>")
	)
	(arc
		(start 95.931482 -241.796824)
		(mid 95.655007 -241.729504)
		(end 95.38081 -241.80546)
		(width 0.088646)
		(layer "In6.Cu")
		(net "M_C_CPU1_SB_DQS_DP<5>")
	)
	(arc
		(start 97.164906 -242.229386)
		(mid 97.077662 -241.987298)
		(end 96.89211 -241.809016)
		(width 0.088646)
		(layer "In6.Cu")
		(net "M_C_CPU1_SB_DQS_DP<5>")
	)
	(arc
		(start 85.17128 -241.750596)
		(mid 84.874422 -241.753862)
		(end 84.616798 -241.606324)
		(width 0.088646)
		(layer "In6.Cu")
		(net "M_C_CPU1_SB_DQS_DP<5>")
	)
	(segment
		(start 29.89453 -235.991654)
		(end 31.972504 -235.991654)
		(width 0.1016)
		(layer "F.Cu")
		(net "M_C_CPU1_SB_DQS_DP<4>")
	)
	(segment
		(start 32.025336 -235.991654)
		(end 32.113982 -235.991654)
		(width 0.20066)
		(layer "F.Cu")
		(net "M_C_CPU1_SB_DQS_DP<4>")
	)
	(segment
		(start 29.50464 -235.991654)
		(end 29.89453 -235.991654)
		(width 0.101854)
		(layer "F.Cu")
		(net "M_C_CPU1_SB_DQS_DP<4>")
	)
	(segment
		(start 94.254066 -239.85347)
		(end 94.253812 -239.853216)
		(width 0.20066)
		(layer "F.Cu")
		(net "M_C_CPU1_SB_DQS_DP<4>")
	)
	(segment
		(start 29.18079 -236.25556)
		(end 29.444696 -235.991654)
		(width 0.20066)
		(layer "F.Cu")
		(net "M_C_CPU1_SB_DQS_DP<4>")
	)
	(segment
		(start 34.120836 -236.677962)
		(end 34.382202 -236.416596)
		(width 0.20066)
		(layer "F.Cu")
		(net "M_C_CPU1_SB_DQS_DP<4>")
	)
	(segment
		(start 29.444696 -235.991654)
		(end 29.50464 -235.991654)
		(width 0.20066)
		(layer "F.Cu")
		(net "M_C_CPU1_SB_DQS_DP<4>")
	)
	(segment
		(start 34.382202 -236.416596)
		(end 34.871914 -236.416596)
		(width 0.20066)
		(layer "F.Cu")
		(net "M_C_CPU1_SB_DQS_DP<4>")
	)
	(segment
		(start 28.398216 -236.677962)
		(end 28.820618 -236.25556)
		(width 0.20066)
		(layer "F.Cu")
		(net "M_C_CPU1_SB_DQS_DP<4>")
	)
	(segment
		(start 94.254066 -240.389156)
		(end 94.254066 -239.85347)
		(width 0.20066)
		(layer "F.Cu")
		(net "M_C_CPU1_SB_DQS_DP<4>")
	)
	(segment
		(start 27.328114 -236.416596)
		(end 27.802586 -236.416596)
		(width 0.20066)
		(layer "F.Cu")
		(net "M_C_CPU1_SB_DQS_DP<4>")
	)
	(segment
		(start 31.972504 -235.991654)
		(end 32.025336 -235.991654)
		(width 0.101854)
		(layer "F.Cu")
		(net "M_C_CPU1_SB_DQS_DP<4>")
	)
	(segment
		(start 32.8803 -236.25302)
		(end 33.516316 -236.677962)
		(width 0.20066)
		(layer "F.Cu")
		(net "M_C_CPU1_SB_DQS_DP<4>")
	)
	(segment
		(start 28.820618 -236.25556)
		(end 29.18079 -236.25556)
		(width 0.20066)
		(layer "F.Cu")
		(net "M_C_CPU1_SB_DQS_DP<4>")
	)
	(segment
		(start 32.375348 -236.25302)
		(end 32.8803 -236.25302)
		(width 0.20066)
		(layer "F.Cu")
		(net "M_C_CPU1_SB_DQS_DP<4>")
	)
	(segment
		(start 33.516316 -236.677962)
		(end 34.120836 -236.677962)
		(width 0.20066)
		(layer "F.Cu")
		(net "M_C_CPU1_SB_DQS_DP<4>")
	)
	(segment
		(start 27.802586 -236.416596)
		(end 28.063952 -236.677962)
		(width 0.20066)
		(layer "F.Cu")
		(net "M_C_CPU1_SB_DQS_DP<4>")
	)
	(segment
		(start 28.063952 -236.677962)
		(end 28.398216 -236.677962)
		(width 0.20066)
		(layer "F.Cu")
		(net "M_C_CPU1_SB_DQS_DP<4>")
	)
	(segment
		(start 35.976814 -236.416596)
		(end 34.871914 -236.416596)
		(width 0.20066)
		(layer "F.Cu")
		(net "M_C_CPU1_SB_DQS_DP<4>")
	)
	(segment
		(start 32.113982 -235.991654)
		(end 32.375348 -236.25302)
		(width 0.20066)
		(layer "F.Cu")
		(net "M_C_CPU1_SB_DQS_DP<4>")
	)
	(segment
		(start 36.976812 -236.898434)
		(end 36.763706 -236.685328)
		(width 0.18288)
		(layer "In4.Cu")
		(net "M_C_CPU1_SB_DQS_DP<4>")
	)
	(segment
		(start 47.41545 -236.256576)
		(end 47.150528 -235.991654)
		(width 0.18288)
		(layer "In4.Cu")
		(net "M_C_CPU1_SB_DQS_DP<4>")
	)
	(segment
		(start 50.606452 -235.406692)
		(end 50.139854 -235.406692)
		(width 0.18288)
		(layer "In4.Cu")
		(net "M_C_CPU1_SB_DQS_DP<4>")
	)
	(segment
		(start 43.844718 -236.087412)
		(end 40.496236 -236.087412)
		(width 0.18288)
		(layer "In4.Cu")
		(net "M_C_CPU1_SB_DQS_DP<4>")
	)
	(segment
		(start 89.287096 -239.355122)
		(end 89.272364 -239.363758)
		(width 0.088646)
		(layer "In4.Cu")
		(net "M_C_CPU1_SB_DQS_DP<4>")
	)
	(segment
		(start 92.106496 -239.355122)
		(end 92.091764 -239.363758)
		(width 0.088646)
		(layer "In4.Cu")
		(net "M_C_CPU1_SB_DQS_DP<4>")
	)
	(segment
		(start 84.13496 -240.228628)
		(end 83.835748 -240.52784)
		(width 0.088646)
		(layer "In4.Cu")
		(net "M_C_CPU1_SB_DQS_DP<4>")
	)
	(segment
		(start 85.608414 -240.177574)
		(end 85.593682 -240.168938)
		(width 0.088646)
		(layer "In4.Cu")
		(net "M_C_CPU1_SB_DQS_DP<4>")
	)
	(segment
		(start 51.520344 -235.41609)
		(end 51.246024 -235.14177)
		(width 0.18288)
		(layer "In4.Cu")
		(net "M_C_CPU1_SB_DQS_DP<4>")
	)
	(segment
		(start 50.871374 -235.14177)
		(end 50.606452 -235.406692)
		(width 0.18288)
		(layer "In4.Cu")
		(net "M_C_CPU1_SB_DQS_DP<4>")
	)
	(segment
		(start 87.407496 -239.355122)
		(end 87.392764 -239.363758)
		(width 0.088646)
		(layer "In4.Cu")
		(net "M_C_CPU1_SB_DQS_DP<4>")
	)
	(segment
		(start 39.685214 -236.898434)
		(end 36.976812 -236.898434)
		(width 0.18288)
		(layer "In4.Cu")
		(net "M_C_CPU1_SB_DQS_DP<4>")
	)
	(segment
		(start 59.426856 -235.684568)
		(end 58.88101 -236.230414)
		(width 0.18288)
		(layer "In4.Cu")
		(net "M_C_CPU1_SB_DQS_DP<4>")
	)
	(segment
		(start 36.245546 -236.685328)
		(end 35.976814 -236.416596)
		(width 0.18288)
		(layer "In4.Cu")
		(net "M_C_CPU1_SB_DQS_DP<4>")
	)
	(segment
		(start 86.467696 -239.355122)
		(end 86.452202 -239.364266)
		(width 0.088646)
		(layer "In4.Cu")
		(net "M_C_CPU1_SB_DQS_DP<4>")
	)
	(segment
		(start 40.496236 -236.087412)
		(end 39.685214 -236.898434)
		(width 0.18288)
		(layer "In4.Cu")
		(net "M_C_CPU1_SB_DQS_DP<4>")
	)
	(segment
		(start 47.150528 -235.991654)
		(end 46.77029 -235.991654)
		(width 0.18288)
		(layer "In4.Cu")
		(net "M_C_CPU1_SB_DQS_DP<4>")
	)
	(segment
		(start 94.253812 -239.853216)
		(end 93.4593 -239.41659)
		(width 0.088646)
		(layer "In4.Cu")
		(net "M_C_CPU1_SB_DQS_DP<4>")
	)
	(segment
		(start 51.246024 -235.14177)
		(end 50.871374 -235.14177)
		(width 0.18288)
		(layer "In4.Cu")
		(net "M_C_CPU1_SB_DQS_DP<4>")
	)
	(segment
		(start 45.18406 -235.647738)
		(end 44.284392 -235.647738)
		(width 0.18288)
		(layer "In4.Cu")
		(net "M_C_CPU1_SB_DQS_DP<4>")
	)
	(segment
		(start 86.452202 -239.364266)
		(end 86.446868 -239.367314)
		(width 0.088646)
		(layer "In4.Cu")
		(net "M_C_CPU1_SB_DQS_DP<4>")
	)
	(segment
		(start 83.835748 -240.52784)
		(end 83.159346 -240.52784)
		(width 0.088646)
		(layer "In4.Cu")
		(net "M_C_CPU1_SB_DQS_DP<4>")
	)
	(segment
		(start 55.61076 -236.230414)
		(end 54.983888 -236.857286)
		(width 0.18288)
		(layer "In4.Cu")
		(net "M_C_CPU1_SB_DQS_DP<4>")
	)
	(segment
		(start 67.853814 -237.137702)
		(end 62.246764 -237.137702)
		(width 0.18288)
		(layer "In4.Cu")
		(net "M_C_CPU1_SB_DQS_DP<4>")
	)
	(segment
		(start 46.49724 -236.264704)
		(end 45.801026 -236.264704)
		(width 0.18288)
		(layer "In4.Cu")
		(net "M_C_CPU1_SB_DQS_DP<4>")
	)
	(segment
		(start 52.802536 -235.41609)
		(end 51.520344 -235.41609)
		(width 0.18288)
		(layer "In4.Cu")
		(net "M_C_CPU1_SB_DQS_DP<4>")
	)
	(segment
		(start 49.28997 -236.256576)
		(end 47.41545 -236.256576)
		(width 0.18288)
		(layer "In4.Cu")
		(net "M_C_CPU1_SB_DQS_DP<4>")
	)
	(segment
		(start 71.184262 -240.46815)
		(end 67.853814 -237.137702)
		(width 0.18288)
		(layer "In4.Cu")
		(net "M_C_CPU1_SB_DQS_DP<4>")
	)
	(segment
		(start 44.284392 -235.647738)
		(end 43.844718 -236.087412)
		(width 0.18288)
		(layer "In4.Cu")
		(net "M_C_CPU1_SB_DQS_DP<4>")
	)
	(segment
		(start 84.855812 -240.228628)
		(end 84.13496 -240.228628)
		(width 0.088646)
		(layer "In4.Cu")
		(net "M_C_CPU1_SB_DQS_DP<4>")
	)
	(segment
		(start 50.139854 -235.406692)
		(end 49.28997 -236.256576)
		(width 0.18288)
		(layer "In4.Cu")
		(net "M_C_CPU1_SB_DQS_DP<4>")
	)
	(segment
		(start 62.246764 -237.137702)
		(end 60.79363 -235.684568)
		(width 0.18288)
		(layer "In4.Cu")
		(net "M_C_CPU1_SB_DQS_DP<4>")
	)
	(segment
		(start 54.983888 -236.857286)
		(end 54.243732 -236.857286)
		(width 0.18288)
		(layer "In4.Cu")
		(net "M_C_CPU1_SB_DQS_DP<4>")
	)
	(segment
		(start 54.243732 -236.857286)
		(end 52.802536 -235.41609)
		(width 0.18288)
		(layer "In4.Cu")
		(net "M_C_CPU1_SB_DQS_DP<4>")
	)
	(segment
		(start 83.099656 -240.46815)
		(end 83.064096 -240.46815)
		(width 0.088646)
		(layer "In4.Cu")
		(net "M_C_CPU1_SB_DQS_DP<4>")
	)
	(segment
		(start 83.064096 -240.46815)
		(end 71.184262 -240.46815)
		(width 0.18288)
		(layer "In4.Cu")
		(net "M_C_CPU1_SB_DQS_DP<4>")
	)
	(segment
		(start 45.801026 -236.264704)
		(end 45.18406 -235.647738)
		(width 0.18288)
		(layer "In4.Cu")
		(net "M_C_CPU1_SB_DQS_DP<4>")
	)
	(segment
		(start 60.79363 -235.684568)
		(end 59.426856 -235.684568)
		(width 0.18288)
		(layer "In4.Cu")
		(net "M_C_CPU1_SB_DQS_DP<4>")
	)
	(segment
		(start 36.763706 -236.685328)
		(end 36.245546 -236.685328)
		(width 0.18288)
		(layer "In4.Cu")
		(net "M_C_CPU1_SB_DQS_DP<4>")
	)
	(segment
		(start 88.347296 -239.355122)
		(end 88.332564 -239.363758)
		(width 0.088646)
		(layer "In4.Cu")
		(net "M_C_CPU1_SB_DQS_DP<4>")
	)
	(segment
		(start 91.166696 -239.355122)
		(end 91.151964 -239.363758)
		(width 0.088646)
		(layer "In4.Cu")
		(net "M_C_CPU1_SB_DQS_DP<4>")
	)
	(segment
		(start 46.77029 -235.991654)
		(end 46.49724 -236.264704)
		(width 0.18288)
		(layer "In4.Cu")
		(net "M_C_CPU1_SB_DQS_DP<4>")
	)
	(segment
		(start 83.159346 -240.52784)
		(end 83.099656 -240.46815)
		(width 0.088646)
		(layer "In4.Cu")
		(net "M_C_CPU1_SB_DQS_DP<4>")
	)
	(segment
		(start 58.88101 -236.230414)
		(end 55.61076 -236.230414)
		(width 0.18288)
		(layer "In4.Cu")
		(net "M_C_CPU1_SB_DQS_DP<4>")
	)
	(arc
		(start 88.332564 -239.363758)
		(mid 88.145366 -239.413901)
		(end 87.958168 -239.363758)
		(width 0.088646)
		(layer "In4.Cu")
		(net "M_C_CPU1_SB_DQS_DP<4>")
	)
	(arc
		(start 91.151964 -239.363758)
		(mid 90.964766 -239.413901)
		(end 90.777568 -239.363758)
		(width 0.088646)
		(layer "In4.Cu")
		(net "M_C_CPU1_SB_DQS_DP<4>")
	)
	(arc
		(start 91.717368 -239.363758)
		(mid 91.443169 -239.287923)
		(end 91.166696 -239.355122)
		(width 0.088646)
		(layer "In4.Cu")
		(net "M_C_CPU1_SB_DQS_DP<4>")
	)
	(arc
		(start 92.091764 -239.363758)
		(mid 91.904566 -239.413901)
		(end 91.717368 -239.363758)
		(width 0.088646)
		(layer "In4.Cu")
		(net "M_C_CPU1_SB_DQS_DP<4>")
	)
	(arc
		(start 88.897968 -239.363758)
		(mid 88.623769 -239.287923)
		(end 88.347296 -239.355122)
		(width 0.088646)
		(layer "In4.Cu")
		(net "M_C_CPU1_SB_DQS_DP<4>")
	)
	(arc
		(start 92.657168 -239.363758)
		(mid 92.382969 -239.287923)
		(end 92.106496 -239.355122)
		(width 0.088646)
		(layer "In4.Cu")
		(net "M_C_CPU1_SB_DQS_DP<4>")
	)
	(arc
		(start 90.777568 -239.363758)
		(mid 90.494866 -239.287982)
		(end 90.212164 -239.363758)
		(width 0.088646)
		(layer "In4.Cu")
		(net "M_C_CPU1_SB_DQS_DP<4>")
	)
	(arc
		(start 93.374718 -239.388904)
		(mid 93.146294 -239.379117)
		(end 92.919296 -239.40643)
		(width 0.088646)
		(layer "In4.Cu")
		(net "M_C_CPU1_SB_DQS_DP<4>")
	)
	(arc
		(start 86.170262 -239.853216)
		(mid 86.17021 -239.860583)
		(end 86.170008 -239.867948)
		(width 0.088646)
		(layer "In4.Cu")
		(net "M_C_CPU1_SB_DQS_DP<4>")
	)
	(arc
		(start 89.837768 -239.363758)
		(mid 89.563569 -239.287923)
		(end 89.287096 -239.355122)
		(width 0.088646)
		(layer "In4.Cu")
		(net "M_C_CPU1_SB_DQS_DP<4>")
	)
	(arc
		(start 86.446868 -239.367314)
		(mid 86.244281 -239.573665)
		(end 86.170262 -239.853216)
		(width 0.088646)
		(layer "In4.Cu")
		(net "M_C_CPU1_SB_DQS_DP<4>")
	)
	(arc
		(start 87.392764 -239.363758)
		(mid 87.205566 -239.413901)
		(end 87.018368 -239.363758)
		(width 0.088646)
		(layer "In4.Cu")
		(net "M_C_CPU1_SB_DQS_DP<4>")
	)
	(arc
		(start 87.018368 -239.363758)
		(mid 86.744169 -239.287923)
		(end 86.467696 -239.355122)
		(width 0.088646)
		(layer "In4.Cu")
		(net "M_C_CPU1_SB_DQS_DP<4>")
	)
	(arc
		(start 85.593682 -240.168938)
		(mid 85.317241 -240.101772)
		(end 85.04301 -240.177574)
		(width 0.088646)
		(layer "In4.Cu")
		(net "M_C_CPU1_SB_DQS_DP<4>")
	)
	(arc
		(start 93.4593 -239.41659)
		(mid 93.418317 -239.398758)
		(end 93.374718 -239.388904)
		(width 0.088646)
		(layer "In4.Cu")
		(net "M_C_CPU1_SB_DQS_DP<4>")
	)
	(arc
		(start 89.272364 -239.363758)
		(mid 89.085166 -239.413901)
		(end 88.897968 -239.363758)
		(width 0.088646)
		(layer "In4.Cu")
		(net "M_C_CPU1_SB_DQS_DP<4>")
	)
	(arc
		(start 85.04301 -240.177574)
		(mid 84.952774 -240.215444)
		(end 84.855812 -240.228628)
		(width 0.088646)
		(layer "In4.Cu")
		(net "M_C_CPU1_SB_DQS_DP<4>")
	)
	(arc
		(start 86.170008 -239.867948)
		(mid 85.976514 -240.181095)
		(end 85.608414 -240.177574)
		(width 0.088646)
		(layer "In4.Cu")
		(net "M_C_CPU1_SB_DQS_DP<4>")
	)
	(arc
		(start 87.958168 -239.363758)
		(mid 87.683969 -239.287923)
		(end 87.407496 -239.355122)
		(width 0.088646)
		(layer "In4.Cu")
		(net "M_C_CPU1_SB_DQS_DP<4>")
	)
	(arc
		(start 90.212164 -239.363758)
		(mid 90.024966 -239.413901)
		(end 89.837768 -239.363758)
		(width 0.088646)
		(layer "In4.Cu")
		(net "M_C_CPU1_SB_DQS_DP<4>")
	)
	(arc
		(start 92.919296 -239.40643)
		(mid 92.784337 -239.409067)
		(end 92.657168 -239.363758)
		(width 0.088646)
		(layer "In4.Cu")
		(net "M_C_CPU1_SB_DQS_DP<4>")
	)
	(segment
		(start 28.942284 -200.880726)
		(end 29.268166 -200.880726)
		(width 0.20066)
		(layer "F.Cu")
		(net "M_C_CPU1_SB_DQS_DP<3>")
	)
	(segment
		(start 25.985724 -201.151236)
		(end 26.20391 -201.151236)
		(width 0.20066)
		(layer "F.Cu")
		(net "M_C_CPU1_SB_DQS_DP<3>")
	)
	(segment
		(start 95.663512 -228.1809)
		(end 95.663766 -228.180646)
		(width 0.20066)
		(layer "F.Cu")
		(net "M_C_CPU1_SB_DQS_DP<3>")
	)
	(segment
		(start 28.529026 -201.141838)
		(end 28.681172 -201.141838)
		(width 0.20066)
		(layer "F.Cu")
		(net "M_C_CPU1_SB_DQS_DP<3>")
	)
	(segment
		(start 29.268166 -200.880726)
		(end 29.693362 -200.45553)
		(width 0.20066)
		(layer "F.Cu")
		(net "M_C_CPU1_SB_DQS_DP<3>")
	)
	(segment
		(start 31.876746 -200.716642)
		(end 30.771846 -200.716642)
		(width 0.20066)
		(layer "F.Cu")
		(net "M_C_CPU1_SB_DQS_DP<3>")
	)
	(segment
		(start 29.693362 -200.45553)
		(end 29.962094 -200.45553)
		(width 0.20066)
		(layer "F.Cu")
		(net "M_C_CPU1_SB_DQS_DP<3>")
	)
	(segment
		(start 23.228046 -200.716642)
		(end 23.766018 -200.716642)
		(width 0.20066)
		(layer "F.Cu")
		(net "M_C_CPU1_SB_DQS_DP<3>")
	)
	(segment
		(start 29.962094 -200.45553)
		(end 30.223206 -200.716642)
		(width 0.20066)
		(layer "F.Cu")
		(net "M_C_CPU1_SB_DQS_DP<3>")
	)
	(segment
		(start 95.663766 -228.180646)
		(end 95.663766 -227.64496)
		(width 0.20066)
		(layer "F.Cu")
		(net "M_C_CPU1_SB_DQS_DP<3>")
	)
	(segment
		(start 30.223206 -200.716642)
		(end 30.771846 -200.716642)
		(width 0.20066)
		(layer "F.Cu")
		(net "M_C_CPU1_SB_DQS_DP<3>")
	)
	(segment
		(start 23.766018 -200.716642)
		(end 24.02713 -200.45553)
		(width 0.20066)
		(layer "F.Cu")
		(net "M_C_CPU1_SB_DQS_DP<3>")
	)
	(segment
		(start 25.715214 -200.880726)
		(end 25.985724 -201.151236)
		(width 0.20066)
		(layer "F.Cu")
		(net "M_C_CPU1_SB_DQS_DP<3>")
	)
	(segment
		(start 28.205684 -201.141838)
		(end 28.529026 -201.141838)
		(width 0.101854)
		(layer "F.Cu")
		(net "M_C_CPU1_SB_DQS_DP<3>")
	)
	(segment
		(start 24.452072 -200.45553)
		(end 25.088088 -200.880726)
		(width 0.20066)
		(layer "F.Cu")
		(net "M_C_CPU1_SB_DQS_DP<3>")
	)
	(segment
		(start 25.088088 -200.880726)
		(end 25.715214 -200.880726)
		(width 0.20066)
		(layer "F.Cu")
		(net "M_C_CPU1_SB_DQS_DP<3>")
	)
	(segment
		(start 26.213308 -201.141838)
		(end 26.45029 -201.141838)
		(width 0.101854)
		(layer "F.Cu")
		(net "M_C_CPU1_SB_DQS_DP<3>")
	)
	(segment
		(start 24.02713 -200.45553)
		(end 24.452072 -200.45553)
		(width 0.20066)
		(layer "F.Cu")
		(net "M_C_CPU1_SB_DQS_DP<3>")
	)
	(segment
		(start 26.45029 -201.141838)
		(end 28.205684 -201.141838)
		(width 0.1016)
		(layer "F.Cu")
		(net "M_C_CPU1_SB_DQS_DP<3>")
	)
	(segment
		(start 26.20391 -201.151236)
		(end 26.213308 -201.141838)
		(width 0.101854)
		(layer "F.Cu")
		(net "M_C_CPU1_SB_DQS_DP<3>")
	)
	(segment
		(start 28.681172 -201.141838)
		(end 28.942284 -200.880726)
		(width 0.20066)
		(layer "F.Cu")
		(net "M_C_CPU1_SB_DQS_DP<3>")
	)
	(segment
		(start 79.939388 -222.755206)
		(end 79.939388 -220.105732)
		(width 0.18288)
		(layer "In6.Cu")
		(net "M_C_CPU1_SB_DQS_DP<3>")
	)
	(segment
		(start 46.507654 -199.168004)
		(end 45.734732 -199.168004)
		(width 0.18288)
		(layer "In6.Cu")
		(net "M_C_CPU1_SB_DQS_DP<3>")
	)
	(segment
		(start 92.278962 -227.659184)
		(end 92.278962 -227.64496)
		(width 0.088646)
		(layer "In6.Cu")
		(net "M_C_CPU1_SB_DQS_DP<3>")
	)
	(segment
		(start 87.018114 -225.69297)
		(end 87.0077 -225.699066)
		(width 0.088646)
		(layer "In6.Cu")
		(net "M_C_CPU1_SB_DQS_DP<3>")
	)
	(segment
		(start 87.862664 -226.506786)
		(end 87.850472 -226.499674)
		(width 0.088646)
		(layer "In6.Cu")
		(net "M_C_CPU1_SB_DQS_DP<3>")
	)
	(segment
		(start 79.939388 -220.105732)
		(end 71.339202 -211.505546)
		(width 0.18288)
		(layer "In6.Cu")
		(net "M_C_CPU1_SB_DQS_DP<3>")
	)
	(segment
		(start 51.245008 -198.590916)
		(end 50.854102 -198.590916)
		(width 0.18288)
		(layer "In6.Cu")
		(net "M_C_CPU1_SB_DQS_DP<3>")
	)
	(segment
		(start 46.78045 -199.4408)
		(end 46.507654 -199.168004)
		(width 0.18288)
		(layer "In6.Cu")
		(net "M_C_CPU1_SB_DQS_DP<3>")
	)
	(segment
		(start 86.078568 -225.69297)
		(end 86.068154 -225.699066)
		(width 0.088646)
		(layer "In6.Cu")
		(net "M_C_CPU1_SB_DQS_DP<3>")
	)
	(segment
		(start 39.88181 -199.173846)
		(end 39.602156 -199.4535)
		(width 0.18288)
		(layer "In6.Cu")
		(net "M_C_CPU1_SB_DQS_DP<3>")
	)
	(segment
		(start 65.81267 -203.398374)
		(end 64.389 -201.974704)
		(width 0.18288)
		(layer "In6.Cu")
		(net "M_C_CPU1_SB_DQS_DP<3>")
	)
	(segment
		(start 33.818322 -200.208896)
		(end 33.206436 -200.208896)
		(width 0.18288)
		(layer "In6.Cu")
		(net "M_C_CPU1_SB_DQS_DP<3>")
	)
	(segment
		(start 71.339202 -211.505546)
		(end 69.251322 -206.421482)
		(width 0.18288)
		(layer "In6.Cu")
		(net "M_C_CPU1_SB_DQS_DP<3>")
	)
	(segment
		(start 82.50301 -223.419924)
		(end 82.479642 -223.419924)
		(width 0.088646)
		(layer "In6.Cu")
		(net "M_C_CPU1_SB_DQS_DP<3>")
	)
	(segment
		(start 36.259008 -201.142346)
		(end 35.780218 -201.142346)
		(width 0.18288)
		(layer "In6.Cu")
		(net "M_C_CPU1_SB_DQS_DP<3>")
	)
	(segment
		(start 38.703504 -199.16394)
		(end 37.907214 -199.49414)
		(width 0.18288)
		(layer "In6.Cu")
		(net "M_C_CPU1_SB_DQS_DP<3>")
	)
	(segment
		(start 32.661352 -200.434702)
		(end 32.158686 -200.434702)
		(width 0.18288)
		(layer "In6.Cu")
		(net "M_C_CPU1_SB_DQS_DP<3>")
	)
	(segment
		(start 44.699174 -198.564246)
		(end 42.539412 -199.459088)
		(width 0.18288)
		(layer "In6.Cu")
		(net "M_C_CPU1_SB_DQS_DP<3>")
	)
	(segment
		(start 87.4014 -225.69805)
		(end 87.39251 -225.69297)
		(width 0.088646)
		(layer "In6.Cu")
		(net "M_C_CPU1_SB_DQS_DP<3>")
	)
	(segment
		(start 88.347296 -227.329238)
		(end 88.332564 -227.320602)
		(width 0.088646)
		(layer "In6.Cu")
		(net "M_C_CPU1_SB_DQS_DP<3>")
	)
	(segment
		(start 39.602156 -199.4535)
		(end 39.239698 -199.4535)
		(width 0.18288)
		(layer "In6.Cu")
		(net "M_C_CPU1_SB_DQS_DP<3>")
	)
	(segment
		(start 82.479642 -223.419924)
		(end 80.604106 -223.419924)
		(width 0.18288)
		(layer "In6.Cu")
		(net "M_C_CPU1_SB_DQS_DP<3>")
	)
	(segment
		(start 40.149526 -199.173846)
		(end 39.88181 -199.173846)
		(width 0.18288)
		(layer "In6.Cu")
		(net "M_C_CPU1_SB_DQS_DP<3>")
	)
	(segment
		(start 91.717114 -227.320602)
		(end 91.7067 -227.326698)
		(width 0.088646)
		(layer "In6.Cu")
		(net "M_C_CPU1_SB_DQS_DP<3>")
	)
	(segment
		(start 83.060032 -223.559624)
		(end 82.860388 -223.35998)
		(width 0.088646)
		(layer "In6.Cu")
		(net "M_C_CPU1_SB_DQS_DP<3>")
	)
	(segment
		(start 64.389 -201.974704)
		(end 59.083448 -199.776334)
		(width 0.18288)
		(layer "In6.Cu")
		(net "M_C_CPU1_SB_DQS_DP<3>")
	)
	(segment
		(start 40.838374 -199.459088)
		(end 40.149526 -199.173846)
		(width 0.18288)
		(layer "In6.Cu")
		(net "M_C_CPU1_SB_DQS_DP<3>")
	)
	(segment
		(start 45.010578 -198.564246)
		(end 44.699174 -198.564246)
		(width 0.18288)
		(layer "In6.Cu")
		(net "M_C_CPU1_SB_DQS_DP<3>")
	)
	(segment
		(start 47.41672 -199.166988)
		(end 47.142908 -199.4408)
		(width 0.18288)
		(layer "In6.Cu")
		(net "M_C_CPU1_SB_DQS_DP<3>")
	)
	(segment
		(start 94.276164 -228.014022)
		(end 94.052644 -228.1428)
		(width 0.088646)
		(layer "In6.Cu")
		(net "M_C_CPU1_SB_DQS_DP<3>")
	)
	(segment
		(start 59.083448 -199.776334)
		(end 53.979572 -199.776334)
		(width 0.18288)
		(layer "In6.Cu")
		(net "M_C_CPU1_SB_DQS_DP<3>")
	)
	(segment
		(start 92.1004 -227.325682)
		(end 92.09151 -227.320602)
		(width 0.088646)
		(layer "In6.Cu")
		(net "M_C_CPU1_SB_DQS_DP<3>")
	)
	(segment
		(start 35.508438 -200.870566)
		(end 34.755074 -200.870566)
		(width 0.18288)
		(layer "In6.Cu")
		(net "M_C_CPU1_SB_DQS_DP<3>")
	)
	(segment
		(start 89.287096 -227.329238)
		(end 89.272364 -227.320602)
		(width 0.088646)
		(layer "In6.Cu")
		(net "M_C_CPU1_SB_DQS_DP<3>")
	)
	(segment
		(start 85.138514 -225.69297)
		(end 85.13445 -225.69551)
		(width 0.088646)
		(layer "In6.Cu")
		(net "M_C_CPU1_SB_DQS_DP<3>")
	)
	(segment
		(start 83.060032 -224.207324)
		(end 83.060032 -223.559624)
		(width 0.088646)
		(layer "In6.Cu")
		(net "M_C_CPU1_SB_DQS_DP<3>")
	)
	(segment
		(start 53.979572 -199.776334)
		(end 52.507388 -198.305166)
		(width 0.18288)
		(layer "In6.Cu")
		(net "M_C_CPU1_SB_DQS_DP<3>")
	)
	(segment
		(start 90.226896 -227.329238)
		(end 90.212164 -227.320602)
		(width 0.088646)
		(layer "In6.Cu")
		(net "M_C_CPU1_SB_DQS_DP<3>")
	)
	(segment
		(start 93.126814 -228.134672)
		(end 93.112082 -228.143308)
		(width 0.088646)
		(layer "In6.Cu")
		(net "M_C_CPU1_SB_DQS_DP<3>")
	)
	(segment
		(start 39.239698 -199.4535)
		(end 38.950138 -199.16394)
		(width 0.18288)
		(layer "In6.Cu")
		(net "M_C_CPU1_SB_DQS_DP<3>")
	)
	(segment
		(start 94.63659 -228.011482)
		(end 94.631764 -228.014022)
		(width 0.088646)
		(layer "In6.Cu")
		(net "M_C_CPU1_SB_DQS_DP<3>")
	)
	(segment
		(start 34.755074 -200.870566)
		(end 34.287714 -200.403206)
		(width 0.18288)
		(layer "In6.Cu")
		(net "M_C_CPU1_SB_DQS_DP<3>")
	)
	(segment
		(start 50.588926 -198.32574)
		(end 50.402744 -198.32574)
		(width 0.18288)
		(layer "In6.Cu")
		(net "M_C_CPU1_SB_DQS_DP<3>")
	)
	(segment
		(start 38.950138 -199.16394)
		(end 38.703504 -199.16394)
		(width 0.18288)
		(layer "In6.Cu")
		(net "M_C_CPU1_SB_DQS_DP<3>")
	)
	(segment
		(start 93.501464 -228.134418)
		(end 93.50121 -228.134672)
		(width 0.088646)
		(layer "In6.Cu")
		(net "M_C_CPU1_SB_DQS_DP<3>")
	)
	(segment
		(start 32.158686 -200.434702)
		(end 31.876746 -200.716642)
		(width 0.18288)
		(layer "In6.Cu")
		(net "M_C_CPU1_SB_DQS_DP<3>")
	)
	(segment
		(start 84.456016 -225.603562)
		(end 84.455762 -225.603054)
		(width 0.088646)
		(layer "In6.Cu")
		(net "M_C_CPU1_SB_DQS_DP<3>")
	)
	(segment
		(start 94.69374 -228.01834)
		(end 94.63659 -228.011482)
		(width 0.088646)
		(layer "In6.Cu")
		(net "M_C_CPU1_SB_DQS_DP<3>")
	)
	(segment
		(start 69.251322 -206.421482)
		(end 66.228214 -203.398374)
		(width 0.18288)
		(layer "In6.Cu")
		(net "M_C_CPU1_SB_DQS_DP<3>")
	)
	(segment
		(start 48.372014 -199.166988)
		(end 47.41672 -199.166988)
		(width 0.18288)
		(layer "In6.Cu")
		(net "M_C_CPU1_SB_DQS_DP<3>")
	)
	(segment
		(start 45.734732 -199.168004)
		(end 45.216064 -198.649336)
		(width 0.18288)
		(layer "In6.Cu")
		(net "M_C_CPU1_SB_DQS_DP<3>")
	)
	(segment
		(start 47.142908 -199.4408)
		(end 46.78045 -199.4408)
		(width 0.18288)
		(layer "In6.Cu")
		(net "M_C_CPU1_SB_DQS_DP<3>")
	)
	(segment
		(start 50.854102 -198.590916)
		(end 50.588926 -198.32574)
		(width 0.18288)
		(layer "In6.Cu")
		(net "M_C_CPU1_SB_DQS_DP<3>")
	)
	(segment
		(start 52.507388 -198.305166)
		(end 51.530758 -198.305166)
		(width 0.18288)
		(layer "In6.Cu")
		(net "M_C_CPU1_SB_DQS_DP<3>")
	)
	(segment
		(start 42.539412 -199.459088)
		(end 40.838374 -199.459088)
		(width 0.18288)
		(layer "In6.Cu")
		(net "M_C_CPU1_SB_DQS_DP<3>")
	)
	(segment
		(start 35.780218 -201.142346)
		(end 35.508438 -200.870566)
		(width 0.18288)
		(layer "In6.Cu")
		(net "M_C_CPU1_SB_DQS_DP<3>")
	)
	(segment
		(start 84.455762 -225.603054)
		(end 83.060032 -224.207324)
		(width 0.088646)
		(layer "In6.Cu")
		(net "M_C_CPU1_SB_DQS_DP<3>")
	)
	(segment
		(start 33.206436 -200.208896)
		(end 32.661352 -200.434702)
		(width 0.18288)
		(layer "In6.Cu")
		(net "M_C_CPU1_SB_DQS_DP<3>")
	)
	(segment
		(start 50.402744 -198.32574)
		(end 48.372014 -199.166988)
		(width 0.18288)
		(layer "In6.Cu")
		(net "M_C_CPU1_SB_DQS_DP<3>")
	)
	(segment
		(start 34.287714 -200.403206)
		(end 33.818322 -200.208896)
		(width 0.18288)
		(layer "In6.Cu")
		(net "M_C_CPU1_SB_DQS_DP<3>")
	)
	(segment
		(start 85.13445 -225.69551)
		(end 85.12048 -225.703384)
		(width 0.088646)
		(layer "In6.Cu")
		(net "M_C_CPU1_SB_DQS_DP<3>")
	)
	(segment
		(start 51.530758 -198.305166)
		(end 51.245008 -198.590916)
		(width 0.18288)
		(layer "In6.Cu")
		(net "M_C_CPU1_SB_DQS_DP<3>")
	)
	(segment
		(start 66.228214 -203.398374)
		(end 65.81267 -203.398374)
		(width 0.18288)
		(layer "In6.Cu")
		(net "M_C_CPU1_SB_DQS_DP<3>")
	)
	(segment
		(start 95.323406 -227.734876)
		(end 94.89821 -227.976684)
		(width 0.088646)
		(layer "In6.Cu")
		(net "M_C_CPU1_SB_DQS_DP<3>")
	)
	(segment
		(start 88.332564 -227.320602)
		(end 88.326468 -227.317046)
		(width 0.088646)
		(layer "In6.Cu")
		(net "M_C_CPU1_SB_DQS_DP<3>")
	)
	(segment
		(start 80.604106 -223.419924)
		(end 79.939388 -222.755206)
		(width 0.18288)
		(layer "In6.Cu")
		(net "M_C_CPU1_SB_DQS_DP<3>")
	)
	(segment
		(start 94.631764 -228.014022)
		(end 94.276164 -228.014022)
		(width 0.088646)
		(layer "In6.Cu")
		(net "M_C_CPU1_SB_DQS_DP<3>")
	)
	(segment
		(start 45.216064 -198.649336)
		(end 45.010578 -198.564246)
		(width 0.18288)
		(layer "In6.Cu")
		(net "M_C_CPU1_SB_DQS_DP<3>")
	)
	(segment
		(start 37.907214 -199.49414)
		(end 36.259008 -201.142346)
		(width 0.18288)
		(layer "In6.Cu")
		(net "M_C_CPU1_SB_DQS_DP<3>")
	)
	(segment
		(start 88.049862 -226.831144)
		(end 88.049862 -226.822508)
		(width 0.088646)
		(layer "In6.Cu")
		(net "M_C_CPU1_SB_DQS_DP<3>")
	)
	(segment
		(start 82.860388 -223.35998)
		(end 82.562954 -223.35998)
		(width 0.088646)
		(layer "In6.Cu")
		(net "M_C_CPU1_SB_DQS_DP<3>")
	)
	(segment
		(start 82.562954 -223.35998)
		(end 82.50301 -223.419924)
		(width 0.088646)
		(layer "In6.Cu")
		(net "M_C_CPU1_SB_DQS_DP<3>")
	)
	(arc
		(start 91.151964 -227.320602)
		(mid 90.964766 -227.270459)
		(end 90.777568 -227.320602)
		(width 0.088646)
		(layer "In6.Cu")
		(net "M_C_CPU1_SB_DQS_DP<3>")
	)
	(arc
		(start 88.049862 -226.822508)
		(mid 87.997592 -226.640143)
		(end 87.862664 -226.506786)
		(width 0.088646)
		(layer "In6.Cu")
		(net "M_C_CPU1_SB_DQS_DP<3>")
	)
	(arc
		(start 95.663766 -227.64496)
		(mid 95.487745 -227.667797)
		(end 95.323406 -227.734876)
		(width 0.088646)
		(layer "In6.Cu")
		(net "M_C_CPU1_SB_DQS_DP<3>")
	)
	(arc
		(start 92.09151 -227.320602)
		(mid 91.904312 -227.270459)
		(end 91.717114 -227.320602)
		(width 0.088646)
		(layer "In6.Cu")
		(net "M_C_CPU1_SB_DQS_DP<3>")
	)
	(arc
		(start 89.837768 -227.320602)
		(mid 89.563569 -227.396437)
		(end 89.287096 -227.329238)
		(width 0.088646)
		(layer "In6.Cu")
		(net "M_C_CPU1_SB_DQS_DP<3>")
	)
	(arc
		(start 87.850472 -226.499674)
		(mid 87.652244 -226.293826)
		(end 87.579962 -226.017328)
		(width 0.088646)
		(layer "In6.Cu")
		(net "M_C_CPU1_SB_DQS_DP<3>")
	)
	(arc
		(start 91.7067 -227.326698)
		(mid 91.428522 -227.396421)
		(end 91.151964 -227.320602)
		(width 0.088646)
		(layer "In6.Cu")
		(net "M_C_CPU1_SB_DQS_DP<3>")
	)
	(arc
		(start 86.452964 -225.69297)
		(mid 86.265766 -225.642827)
		(end 86.078568 -225.69297)
		(width 0.088646)
		(layer "In6.Cu")
		(net "M_C_CPU1_SB_DQS_DP<3>")
	)
	(arc
		(start 94.052644 -228.1428)
		(mid 93.775979 -228.210271)
		(end 93.501464 -228.134418)
		(width 0.088646)
		(layer "In6.Cu")
		(net "M_C_CPU1_SB_DQS_DP<3>")
	)
	(arc
		(start 84.572856 -225.692208)
		(mid 84.563276 -225.686585)
		(end 84.553806 -225.680778)
		(width 0.088646)
		(layer "In6.Cu")
		(net "M_C_CPU1_SB_DQS_DP<3>")
	)
	(arc
		(start 93.112082 -228.143308)
		(mid 92.835641 -228.210474)
		(end 92.56141 -228.134672)
		(width 0.088646)
		(layer "In6.Cu")
		(net "M_C_CPU1_SB_DQS_DP<3>")
	)
	(arc
		(start 87.39251 -225.69297)
		(mid 87.205312 -225.642827)
		(end 87.018114 -225.69297)
		(width 0.088646)
		(layer "In6.Cu")
		(net "M_C_CPU1_SB_DQS_DP<3>")
	)
	(arc
		(start 94.89821 -227.976684)
		(mid 94.799368 -228.014194)
		(end 94.69374 -228.01834)
		(width 0.088646)
		(layer "In6.Cu")
		(net "M_C_CPU1_SB_DQS_DP<3>")
	)
	(arc
		(start 87.579962 -226.017328)
		(mid 87.532283 -225.834428)
		(end 87.4014 -225.69805)
		(width 0.088646)
		(layer "In6.Cu")
		(net "M_C_CPU1_SB_DQS_DP<3>")
	)
	(arc
		(start 93.50121 -228.134672)
		(mid 93.314012 -228.084529)
		(end 93.126814 -228.134672)
		(width 0.088646)
		(layer "In6.Cu")
		(net "M_C_CPU1_SB_DQS_DP<3>")
	)
	(arc
		(start 86.068154 -225.699066)
		(mid 85.789722 -225.76888)
		(end 85.51291 -225.69297)
		(width 0.088646)
		(layer "In6.Cu")
		(net "M_C_CPU1_SB_DQS_DP<3>")
	)
	(arc
		(start 92.278962 -227.64496)
		(mid 92.231283 -227.46206)
		(end 92.1004 -227.325682)
		(width 0.088646)
		(layer "In6.Cu")
		(net "M_C_CPU1_SB_DQS_DP<3>")
	)
	(arc
		(start 87.0077 -225.699066)
		(mid 86.729522 -225.768758)
		(end 86.452964 -225.69297)
		(width 0.088646)
		(layer "In6.Cu")
		(net "M_C_CPU1_SB_DQS_DP<3>")
	)
	(arc
		(start 90.777568 -227.320602)
		(mid 90.503369 -227.396437)
		(end 90.226896 -227.329238)
		(width 0.088646)
		(layer "In6.Cu")
		(net "M_C_CPU1_SB_DQS_DP<3>")
	)
	(arc
		(start 88.326468 -227.317046)
		(mid 88.123881 -227.110695)
		(end 88.049862 -226.831144)
		(width 0.088646)
		(layer "In6.Cu")
		(net "M_C_CPU1_SB_DQS_DP<3>")
	)
	(arc
		(start 84.553806 -225.680778)
		(mid 84.502777 -225.644872)
		(end 84.456016 -225.603562)
		(width 0.088646)
		(layer "In6.Cu")
		(net "M_C_CPU1_SB_DQS_DP<3>")
	)
	(arc
		(start 90.212164 -227.320602)
		(mid 90.024966 -227.270459)
		(end 89.837768 -227.320602)
		(width 0.088646)
		(layer "In6.Cu")
		(net "M_C_CPU1_SB_DQS_DP<3>")
	)
	(arc
		(start 92.56141 -228.134672)
		(mid 92.358105 -227.933806)
		(end 92.278962 -227.659184)
		(width 0.088646)
		(layer "In6.Cu")
		(net "M_C_CPU1_SB_DQS_DP<3>")
	)
	(arc
		(start 89.272364 -227.320602)
		(mid 89.085166 -227.270459)
		(end 88.897968 -227.320602)
		(width 0.088646)
		(layer "In6.Cu")
		(net "M_C_CPU1_SB_DQS_DP<3>")
	)
	(arc
		(start 85.51291 -225.69297)
		(mid 85.325712 -225.642827)
		(end 85.138514 -225.69297)
		(width 0.088646)
		(layer "In6.Cu")
		(net "M_C_CPU1_SB_DQS_DP<3>")
	)
	(arc
		(start 85.12048 -225.703384)
		(mid 84.845233 -225.768505)
		(end 84.572856 -225.692208)
		(width 0.088646)
		(layer "In6.Cu")
		(net "M_C_CPU1_SB_DQS_DP<3>")
	)
	(arc
		(start 88.897968 -227.320602)
		(mid 88.623769 -227.396437)
		(end 88.347296 -227.329238)
		(width 0.088646)
		(layer "In6.Cu")
		(net "M_C_CPU1_SB_DQS_DP<3>")
	)
	(segment
		(start 28.681172 -210.491832)
		(end 28.942284 -210.23072)
		(width 0.20066)
		(layer "F.Cu")
		(net "M_C_CPU1_SB_DQS_DP<2>")
	)
	(segment
		(start 25.088088 -210.23072)
		(end 25.715214 -210.23072)
		(width 0.20066)
		(layer "F.Cu")
		(net "M_C_CPU1_SB_DQS_DP<2>")
	)
	(segment
		(start 29.268166 -210.23072)
		(end 29.693362 -209.805524)
		(width 0.20066)
		(layer "F.Cu")
		(net "M_C_CPU1_SB_DQS_DP<2>")
	)
	(segment
		(start 25.985724 -210.50123)
		(end 26.20391 -210.50123)
		(width 0.20066)
		(layer "F.Cu")
		(net "M_C_CPU1_SB_DQS_DP<2>")
	)
	(segment
		(start 28.205684 -210.491832)
		(end 28.529026 -210.491832)
		(width 0.101854)
		(layer "F.Cu")
		(net "M_C_CPU1_SB_DQS_DP<2>")
	)
	(segment
		(start 24.02713 -209.805524)
		(end 24.452072 -209.805524)
		(width 0.20066)
		(layer "F.Cu")
		(net "M_C_CPU1_SB_DQS_DP<2>")
	)
	(segment
		(start 25.715214 -210.23072)
		(end 25.985724 -210.50123)
		(width 0.20066)
		(layer "F.Cu")
		(net "M_C_CPU1_SB_DQS_DP<2>")
	)
	(segment
		(start 23.228046 -210.066636)
		(end 23.766018 -210.066636)
		(width 0.20066)
		(layer "F.Cu")
		(net "M_C_CPU1_SB_DQS_DP<2>")
	)
	(segment
		(start 28.942284 -210.23072)
		(end 29.268166 -210.23072)
		(width 0.20066)
		(layer "F.Cu")
		(net "M_C_CPU1_SB_DQS_DP<2>")
	)
	(segment
		(start 23.766018 -210.066636)
		(end 24.02713 -209.805524)
		(width 0.20066)
		(layer "F.Cu")
		(net "M_C_CPU1_SB_DQS_DP<2>")
	)
	(segment
		(start 26.20391 -210.50123)
		(end 26.213308 -210.491832)
		(width 0.101854)
		(layer "F.Cu")
		(net "M_C_CPU1_SB_DQS_DP<2>")
	)
	(segment
		(start 31.876746 -210.066636)
		(end 30.771846 -210.066636)
		(width 0.20066)
		(layer "F.Cu")
		(net "M_C_CPU1_SB_DQS_DP<2>")
	)
	(segment
		(start 24.452072 -209.805524)
		(end 25.088088 -210.23072)
		(width 0.20066)
		(layer "F.Cu")
		(net "M_C_CPU1_SB_DQS_DP<2>")
	)
	(segment
		(start 29.962094 -209.805524)
		(end 30.223206 -210.066636)
		(width 0.20066)
		(layer "F.Cu")
		(net "M_C_CPU1_SB_DQS_DP<2>")
	)
	(segment
		(start 92.374466 -230.622602)
		(end 92.374466 -230.086916)
		(width 0.20066)
		(layer "F.Cu")
		(net "M_C_CPU1_SB_DQS_DP<2>")
	)
	(segment
		(start 29.693362 -209.805524)
		(end 29.962094 -209.805524)
		(width 0.20066)
		(layer "F.Cu")
		(net "M_C_CPU1_SB_DQS_DP<2>")
	)
	(segment
		(start 92.374466 -230.086916)
		(end 92.374212 -230.086662)
		(width 0.20066)
		(layer "F.Cu")
		(net "M_C_CPU1_SB_DQS_DP<2>")
	)
	(segment
		(start 26.45029 -210.491832)
		(end 28.205684 -210.491832)
		(width 0.1016)
		(layer "F.Cu")
		(net "M_C_CPU1_SB_DQS_DP<2>")
	)
	(segment
		(start 28.529026 -210.491832)
		(end 28.681172 -210.491832)
		(width 0.20066)
		(layer "F.Cu")
		(net "M_C_CPU1_SB_DQS_DP<2>")
	)
	(segment
		(start 26.213308 -210.491832)
		(end 26.45029 -210.491832)
		(width 0.101854)
		(layer "F.Cu")
		(net "M_C_CPU1_SB_DQS_DP<2>")
	)
	(segment
		(start 30.223206 -210.066636)
		(end 30.771846 -210.066636)
		(width 0.20066)
		(layer "F.Cu")
		(net "M_C_CPU1_SB_DQS_DP<2>")
	)
	(segment
		(start 88.903556 -230.572818)
		(end 88.893142 -230.57866)
		(width 0.088646)
		(layer "In4.Cu")
		(net "M_C_CPU1_SB_DQS_DP<2>")
	)
	(segment
		(start 66.605404 -213.001352)
		(end 66.383916 -212.77961)
		(width 0.18288)
		(layer "In4.Cu")
		(net "M_C_CPU1_SB_DQS_DP<2>")
	)
	(segment
		(start 66.383916 -212.77961)
		(end 64.108076 -212.77961)
		(width 0.18288)
		(layer "In4.Cu")
		(net "M_C_CPU1_SB_DQS_DP<2>")
	)
	(segment
		(start 35.500056 -210.216496)
		(end 34.913062 -210.216496)
		(width 0.18288)
		(layer "In4.Cu")
		(net "M_C_CPU1_SB_DQS_DP<2>")
	)
	(segment
		(start 86.467696 -230.584756)
		(end 86.452964 -230.57612)
		(width 0.088646)
		(layer "In4.Cu")
		(net "M_C_CPU1_SB_DQS_DP<2>")
	)
	(segment
		(start 89.287096 -230.584756)
		(end 89.272364 -230.57612)
		(width 0.088646)
		(layer "In4.Cu")
		(net "M_C_CPU1_SB_DQS_DP<2>")
	)
	(segment
		(start 84.588096 -230.584756)
		(end 84.573364 -230.57612)
		(width 0.088646)
		(layer "In4.Cu")
		(net "M_C_CPU1_SB_DQS_DP<2>")
	)
	(segment
		(start 85.527896 -230.584756)
		(end 85.513164 -230.57612)
		(width 0.088646)
		(layer "In4.Cu")
		(net "M_C_CPU1_SB_DQS_DP<2>")
	)
	(segment
		(start 70.504304 -222.409766)
		(end 67.387978 -214.889842)
		(width 0.18288)
		(layer "In4.Cu")
		(net "M_C_CPU1_SB_DQS_DP<2>")
	)
	(segment
		(start 44.43476 -211.995512)
		(end 43.524678 -211.08543)
		(width 0.18288)
		(layer "In4.Cu")
		(net "M_C_CPU1_SB_DQS_DP<2>")
	)
	(segment
		(start 34.913062 -210.216496)
		(end 34.277554 -209.580988)
		(width 0.18288)
		(layer "In4.Cu")
		(net "M_C_CPU1_SB_DQS_DP<2>")
	)
	(segment
		(start 32.158178 -209.785204)
		(end 31.876746 -210.066636)
		(width 0.18288)
		(layer "In4.Cu")
		(net "M_C_CPU1_SB_DQS_DP<2>")
	)
	(segment
		(start 82.708496 -229.483666)
		(end 77.578204 -229.483666)
		(width 0.18288)
		(layer "In4.Cu")
		(net "M_C_CPU1_SB_DQS_DP<2>")
	)
	(segment
		(start 61.969142 -211.893912)
		(end 59.609228 -211.893912)
		(width 0.18288)
		(layer "In4.Cu")
		(net "M_C_CPU1_SB_DQS_DP<2>")
	)
	(segment
		(start 50.304446 -211.916518)
		(end 49.446434 -212.77453)
		(width 0.18288)
		(layer "In4.Cu")
		(net "M_C_CPU1_SB_DQS_DP<2>")
	)
	(segment
		(start 90.21191 -230.57612)
		(end 90.212164 -230.57612)
		(width 0.088646)
		(layer "In4.Cu")
		(net "M_C_CPU1_SB_DQS_DP<2>")
	)
	(segment
		(start 51.236372 -212.191854)
		(end 50.86858 -212.191854)
		(width 0.18288)
		(layer "In4.Cu")
		(net "M_C_CPU1_SB_DQS_DP<2>")
	)
	(segment
		(start 92.033852 -230.176578)
		(end 91.608656 -230.418386)
		(width 0.088646)
		(layer "In4.Cu")
		(net "M_C_CPU1_SB_DQS_DP<2>")
	)
	(segment
		(start 64.108076 -212.77961)
		(end 61.969142 -211.893912)
		(width 0.18288)
		(layer "In4.Cu")
		(net "M_C_CPU1_SB_DQS_DP<2>")
	)
	(segment
		(start 82.731864 -229.483666)
		(end 82.708496 -229.483666)
		(width 0.088646)
		(layer "In4.Cu")
		(net "M_C_CPU1_SB_DQS_DP<2>")
	)
	(segment
		(start 46.492668 -212.766148)
		(end 45.824394 -212.766148)
		(width 0.18288)
		(layer "In4.Cu")
		(net "M_C_CPU1_SB_DQS_DP<2>")
	)
	(segment
		(start 67.388232 -214.889842)
		(end 66.605404 -213.001352)
		(width 0.18288)
		(layer "In4.Cu")
		(net "M_C_CPU1_SB_DQS_DP<2>")
	)
	(segment
		(start 82.791808 -229.423722)
		(end 82.731864 -229.483666)
		(width 0.088646)
		(layer "In4.Cu")
		(net "M_C_CPU1_SB_DQS_DP<2>")
	)
	(segment
		(start 33.08477 -209.580988)
		(end 32.880554 -209.785204)
		(width 0.18288)
		(layer "In4.Cu")
		(net "M_C_CPU1_SB_DQS_DP<2>")
	)
	(segment
		(start 34.277554 -209.580988)
		(end 33.08477 -209.580988)
		(width 0.18288)
		(layer "In4.Cu")
		(net "M_C_CPU1_SB_DQS_DP<2>")
	)
	(segment
		(start 32.880554 -209.785204)
		(end 32.158178 -209.785204)
		(width 0.18288)
		(layer "In4.Cu")
		(net "M_C_CPU1_SB_DQS_DP<2>")
	)
	(segment
		(start 36.250372 -210.491832)
		(end 35.775392 -210.491832)
		(width 0.18288)
		(layer "In4.Cu")
		(net "M_C_CPU1_SB_DQS_DP<2>")
	)
	(segment
		(start 91.347036 -230.453184)
		(end 91.34221 -230.455724)
		(width 0.088646)
		(layer "In4.Cu")
		(net "M_C_CPU1_SB_DQS_DP<2>")
	)
	(segment
		(start 45.824394 -212.766148)
		(end 45.053758 -211.995512)
		(width 0.18288)
		(layer "In4.Cu")
		(net "M_C_CPU1_SB_DQS_DP<2>")
	)
	(segment
		(start 46.768512 -213.041992)
		(end 46.492668 -212.766148)
		(width 0.18288)
		(layer "In4.Cu")
		(net "M_C_CPU1_SB_DQS_DP<2>")
	)
	(segment
		(start 47.419514 -212.77453)
		(end 47.152052 -213.041992)
		(width 0.18288)
		(layer "In4.Cu")
		(net "M_C_CPU1_SB_DQS_DP<2>")
	)
	(segment
		(start 45.053758 -211.995512)
		(end 44.43476 -211.995512)
		(width 0.18288)
		(layer "In4.Cu")
		(net "M_C_CPU1_SB_DQS_DP<2>")
	)
	(segment
		(start 35.775392 -210.491832)
		(end 35.500056 -210.216496)
		(width 0.18288)
		(layer "In4.Cu")
		(net "M_C_CPU1_SB_DQS_DP<2>")
	)
	(segment
		(start 83.394042 -229.843584)
		(end 83.394042 -229.752906)
		(width 0.088646)
		(layer "In4.Cu")
		(net "M_C_CPU1_SB_DQS_DP<2>")
	)
	(segment
		(start 77.578204 -229.483666)
		(end 70.504304 -222.409766)
		(width 0.18288)
		(layer "In4.Cu")
		(net "M_C_CPU1_SB_DQS_DP<2>")
	)
	(segment
		(start 55.028338 -211.934044)
		(end 51.494182 -211.934044)
		(width 0.18288)
		(layer "In4.Cu")
		(net "M_C_CPU1_SB_DQS_DP<2>")
	)
	(segment
		(start 36.514278 -210.227926)
		(end 36.250372 -210.491832)
		(width 0.18288)
		(layer "In4.Cu")
		(net "M_C_CPU1_SB_DQS_DP<2>")
	)
	(segment
		(start 50.593244 -211.916518)
		(end 50.304446 -211.916518)
		(width 0.18288)
		(layer "In4.Cu")
		(net "M_C_CPU1_SB_DQS_DP<2>")
	)
	(segment
		(start 58.876184 -211.160868)
		(end 55.801514 -211.160868)
		(width 0.18288)
		(layer "In4.Cu")
		(net "M_C_CPU1_SB_DQS_DP<2>")
	)
	(segment
		(start 91.34221 -230.455724)
		(end 90.98661 -230.455724)
		(width 0.088646)
		(layer "In4.Cu")
		(net "M_C_CPU1_SB_DQS_DP<2>")
	)
	(segment
		(start 39.619428 -210.227926)
		(end 36.514278 -210.227926)
		(width 0.18288)
		(layer "In4.Cu")
		(net "M_C_CPU1_SB_DQS_DP<2>")
	)
	(segment
		(start 51.494182 -211.934044)
		(end 51.236372 -212.191854)
		(width 0.18288)
		(layer "In4.Cu")
		(net "M_C_CPU1_SB_DQS_DP<2>")
	)
	(segment
		(start 90.98661 -230.455724)
		(end 90.76309 -230.584502)
		(width 0.088646)
		(layer "In4.Cu")
		(net "M_C_CPU1_SB_DQS_DP<2>")
	)
	(segment
		(start 40.476932 -211.08543)
		(end 39.619428 -210.227926)
		(width 0.18288)
		(layer "In4.Cu")
		(net "M_C_CPU1_SB_DQS_DP<2>")
	)
	(segment
		(start 59.609228 -211.893912)
		(end 58.876184 -211.160868)
		(width 0.18288)
		(layer "In4.Cu")
		(net "M_C_CPU1_SB_DQS_DP<2>")
	)
	(segment
		(start 91.404186 -230.460042)
		(end 91.347036 -230.453184)
		(width 0.088646)
		(layer "In4.Cu")
		(net "M_C_CPU1_SB_DQS_DP<2>")
	)
	(segment
		(start 49.446434 -212.77453)
		(end 47.419514 -212.77453)
		(width 0.18288)
		(layer "In4.Cu")
		(net "M_C_CPU1_SB_DQS_DP<2>")
	)
	(segment
		(start 50.86858 -212.191854)
		(end 50.593244 -211.916518)
		(width 0.18288)
		(layer "In4.Cu")
		(net "M_C_CPU1_SB_DQS_DP<2>")
	)
	(segment
		(start 83.855052 -230.304594)
		(end 83.394042 -229.843584)
		(width 0.088646)
		(layer "In4.Cu")
		(net "M_C_CPU1_SB_DQS_DP<2>")
	)
	(segment
		(start 47.152052 -213.041992)
		(end 46.768512 -213.041992)
		(width 0.18288)
		(layer "In4.Cu")
		(net "M_C_CPU1_SB_DQS_DP<2>")
	)
	(segment
		(start 67.387978 -214.889842)
		(end 67.388232 -214.889842)
		(width 0.18288)
		(layer "In4.Cu")
		(net "M_C_CPU1_SB_DQS_DP<2>")
	)
	(segment
		(start 55.801514 -211.160868)
		(end 55.028338 -211.934044)
		(width 0.18288)
		(layer "In4.Cu")
		(net "M_C_CPU1_SB_DQS_DP<2>")
	)
	(segment
		(start 43.524678 -211.08543)
		(end 40.476932 -211.08543)
		(width 0.18288)
		(layer "In4.Cu")
		(net "M_C_CPU1_SB_DQS_DP<2>")
	)
	(segment
		(start 83.064858 -229.423722)
		(end 82.791808 -229.423722)
		(width 0.088646)
		(layer "In4.Cu")
		(net "M_C_CPU1_SB_DQS_DP<2>")
	)
	(segment
		(start 83.394042 -229.752906)
		(end 83.064858 -229.423722)
		(width 0.088646)
		(layer "In4.Cu")
		(net "M_C_CPU1_SB_DQS_DP<2>")
	)
	(segment
		(start 87.407496 -230.584756)
		(end 87.392764 -230.57612)
		(width 0.088646)
		(layer "In4.Cu")
		(net "M_C_CPU1_SB_DQS_DP<2>")
	)
	(arc
		(start 86.452964 -230.57612)
		(mid 86.265766 -230.525977)
		(end 86.078568 -230.57612)
		(width 0.088646)
		(layer "In4.Cu")
		(net "M_C_CPU1_SB_DQS_DP<2>")
	)
	(arc
		(start 89.272364 -230.57612)
		(mid 89.08841 -230.525991)
		(end 88.903556 -230.572818)
		(width 0.088646)
		(layer "In4.Cu")
		(net "M_C_CPU1_SB_DQS_DP<2>")
	)
	(arc
		(start 87.018368 -230.57612)
		(mid 86.744169 -230.651955)
		(end 86.467696 -230.584756)
		(width 0.088646)
		(layer "In4.Cu")
		(net "M_C_CPU1_SB_DQS_DP<2>")
	)
	(arc
		(start 84.573364 -230.57612)
		(mid 84.571082 -230.574842)
		(end 84.568792 -230.57358)
		(width 0.088646)
		(layer "In4.Cu")
		(net "M_C_CPU1_SB_DQS_DP<2>")
	)
	(arc
		(start 84.386928 -230.525574)
		(mid 84.099123 -230.46774)
		(end 83.855052 -230.304594)
		(width 0.088646)
		(layer "In4.Cu")
		(net "M_C_CPU1_SB_DQS_DP<2>")
	)
	(arc
		(start 87.392764 -230.57612)
		(mid 87.205566 -230.525977)
		(end 87.018368 -230.57612)
		(width 0.088646)
		(layer "In4.Cu")
		(net "M_C_CPU1_SB_DQS_DP<2>")
	)
	(arc
		(start 86.078568 -230.57612)
		(mid 85.804369 -230.651955)
		(end 85.527896 -230.584756)
		(width 0.088646)
		(layer "In4.Cu")
		(net "M_C_CPU1_SB_DQS_DP<2>")
	)
	(arc
		(start 85.138768 -230.57612)
		(mid 84.864569 -230.651955)
		(end 84.588096 -230.584756)
		(width 0.088646)
		(layer "In4.Cu")
		(net "M_C_CPU1_SB_DQS_DP<2>")
	)
	(arc
		(start 88.332564 -230.57612)
		(mid 88.145366 -230.525977)
		(end 87.958168 -230.57612)
		(width 0.088646)
		(layer "In4.Cu")
		(net "M_C_CPU1_SB_DQS_DP<2>")
	)
	(arc
		(start 92.374212 -230.086662)
		(mid 92.198191 -230.109499)
		(end 92.033852 -230.176578)
		(width 0.088646)
		(layer "In4.Cu")
		(net "M_C_CPU1_SB_DQS_DP<2>")
	)
	(arc
		(start 85.513164 -230.57612)
		(mid 85.325966 -230.525977)
		(end 85.138768 -230.57612)
		(width 0.088646)
		(layer "In4.Cu")
		(net "M_C_CPU1_SB_DQS_DP<2>")
	)
	(arc
		(start 88.893142 -230.57866)
		(mid 88.612507 -230.651828)
		(end 88.332564 -230.57612)
		(width 0.088646)
		(layer "In4.Cu")
		(net "M_C_CPU1_SB_DQS_DP<2>")
	)
	(arc
		(start 87.958168 -230.57612)
		(mid 87.683969 -230.651955)
		(end 87.407496 -230.584756)
		(width 0.088646)
		(layer "In4.Cu")
		(net "M_C_CPU1_SB_DQS_DP<2>")
	)
	(arc
		(start 91.608656 -230.418386)
		(mid 91.509814 -230.455896)
		(end 91.404186 -230.460042)
		(width 0.088646)
		(layer "In4.Cu")
		(net "M_C_CPU1_SB_DQS_DP<2>")
	)
	(arc
		(start 90.212164 -230.57612)
		(mid 90.024966 -230.525977)
		(end 89.837768 -230.57612)
		(width 0.088646)
		(layer "In4.Cu")
		(net "M_C_CPU1_SB_DQS_DP<2>")
	)
	(arc
		(start 89.837768 -230.57612)
		(mid 89.563569 -230.651955)
		(end 89.287096 -230.584756)
		(width 0.088646)
		(layer "In4.Cu")
		(net "M_C_CPU1_SB_DQS_DP<2>")
	)
	(arc
		(start 84.568792 -230.57358)
		(mid 84.480919 -230.538002)
		(end 84.386928 -230.525574)
		(width 0.088646)
		(layer "In4.Cu")
		(net "M_C_CPU1_SB_DQS_DP<2>")
	)
	(arc
		(start 90.76309 -230.584502)
		(mid 90.486425 -230.651973)
		(end 90.21191 -230.57612)
		(width 0.088646)
		(layer "In4.Cu")
		(net "M_C_CPU1_SB_DQS_DP<2>")
	)
	(segment
		(start 28.942284 -219.580714)
		(end 29.268166 -219.580714)
		(width 0.20066)
		(layer "F.Cu")
		(net "M_C_CPU1_SB_DQS_DP<1>")
	)
	(segment
		(start 95.663512 -237.947454)
		(end 95.663766 -237.9472)
		(width 0.20066)
		(layer "F.Cu")
		(net "M_C_CPU1_SB_DQS_DP<1>")
	)
	(segment
		(start 26.213308 -219.841826)
		(end 26.45029 -219.841826)
		(width 0.101854)
		(layer "F.Cu")
		(net "M_C_CPU1_SB_DQS_DP<1>")
	)
	(segment
		(start 25.985724 -219.851224)
		(end 26.20391 -219.851224)
		(width 0.20066)
		(layer "F.Cu")
		(net "M_C_CPU1_SB_DQS_DP<1>")
	)
	(segment
		(start 29.268166 -219.580714)
		(end 29.693362 -219.155518)
		(width 0.20066)
		(layer "F.Cu")
		(net "M_C_CPU1_SB_DQS_DP<1>")
	)
	(segment
		(start 23.228046 -219.41663)
		(end 23.766018 -219.41663)
		(width 0.20066)
		(layer "F.Cu")
		(net "M_C_CPU1_SB_DQS_DP<1>")
	)
	(segment
		(start 26.20391 -219.851224)
		(end 26.213308 -219.841826)
		(width 0.101854)
		(layer "F.Cu")
		(net "M_C_CPU1_SB_DQS_DP<1>")
	)
	(segment
		(start 29.693362 -219.155518)
		(end 29.962094 -219.155518)
		(width 0.20066)
		(layer "F.Cu")
		(net "M_C_CPU1_SB_DQS_DP<1>")
	)
	(segment
		(start 26.45029 -219.841826)
		(end 28.205684 -219.841826)
		(width 0.1016)
		(layer "F.Cu")
		(net "M_C_CPU1_SB_DQS_DP<1>")
	)
	(segment
		(start 95.663766 -237.9472)
		(end 95.663766 -237.411514)
		(width 0.20066)
		(layer "F.Cu")
		(net "M_C_CPU1_SB_DQS_DP<1>")
	)
	(segment
		(start 24.452072 -219.155518)
		(end 25.088088 -219.580714)
		(width 0.20066)
		(layer "F.Cu")
		(net "M_C_CPU1_SB_DQS_DP<1>")
	)
	(segment
		(start 28.681172 -219.841826)
		(end 28.942284 -219.580714)
		(width 0.20066)
		(layer "F.Cu")
		(net "M_C_CPU1_SB_DQS_DP<1>")
	)
	(segment
		(start 30.223206 -219.41663)
		(end 30.771846 -219.41663)
		(width 0.20066)
		(layer "F.Cu")
		(net "M_C_CPU1_SB_DQS_DP<1>")
	)
	(segment
		(start 28.205684 -219.841826)
		(end 28.529026 -219.841826)
		(width 0.101854)
		(layer "F.Cu")
		(net "M_C_CPU1_SB_DQS_DP<1>")
	)
	(segment
		(start 24.02713 -219.155518)
		(end 24.452072 -219.155518)
		(width 0.20066)
		(layer "F.Cu")
		(net "M_C_CPU1_SB_DQS_DP<1>")
	)
	(segment
		(start 23.766018 -219.41663)
		(end 24.02713 -219.155518)
		(width 0.20066)
		(layer "F.Cu")
		(net "M_C_CPU1_SB_DQS_DP<1>")
	)
	(segment
		(start 29.962094 -219.155518)
		(end 30.223206 -219.41663)
		(width 0.20066)
		(layer "F.Cu")
		(net "M_C_CPU1_SB_DQS_DP<1>")
	)
	(segment
		(start 25.088088 -219.580714)
		(end 25.715214 -219.580714)
		(width 0.20066)
		(layer "F.Cu")
		(net "M_C_CPU1_SB_DQS_DP<1>")
	)
	(segment
		(start 28.529026 -219.841826)
		(end 28.681172 -219.841826)
		(width 0.20066)
		(layer "F.Cu")
		(net "M_C_CPU1_SB_DQS_DP<1>")
	)
	(segment
		(start 25.715214 -219.580714)
		(end 25.985724 -219.851224)
		(width 0.20066)
		(layer "F.Cu")
		(net "M_C_CPU1_SB_DQS_DP<1>")
	)
	(segment
		(start 31.876746 -219.41663)
		(end 30.771846 -219.41663)
		(width 0.20066)
		(layer "F.Cu")
		(net "M_C_CPU1_SB_DQS_DP<1>")
	)
	(segment
		(start 63.649098 -225.387662)
		(end 63.337186 -225.07575)
		(width 0.18288)
		(layer "In6.Cu")
		(net "M_C_CPU1_SB_DQS_DP<1>")
	)
	(segment
		(start 55.343298 -222.373698)
		(end 54.767734 -222.949262)
		(width 0.18288)
		(layer "In6.Cu")
		(net "M_C_CPU1_SB_DQS_DP<1>")
	)
	(segment
		(start 83.422236 -235.782612)
		(end 83.095592 -235.455968)
		(width 0.088646)
		(layer "In6.Cu")
		(net "M_C_CPU1_SB_DQS_DP<1>")
	)
	(segment
		(start 35.731196 -219.842334)
		(end 35.455098 -219.566236)
		(width 0.18288)
		(layer "In6.Cu")
		(net "M_C_CPU1_SB_DQS_DP<1>")
	)
	(segment
		(start 54.767734 -222.949262)
		(end 51.59883 -222.949262)
		(width 0.18288)
		(layer "In6.Cu")
		(net "M_C_CPU1_SB_DQS_DP<1>")
	)
	(segment
		(start 46.45279 -222.116142)
		(end 45.985176 -222.116142)
		(width 0.18288)
		(layer "In6.Cu")
		(net "M_C_CPU1_SB_DQS_DP<1>")
	)
	(segment
		(start 47.485808 -222.132652)
		(end 47.22495 -222.39351)
		(width 0.18288)
		(layer "In6.Cu")
		(net "M_C_CPU1_SB_DQS_DP<1>")
	)
	(segment
		(start 93.501464 -237.900972)
		(end 93.50121 -237.901226)
		(width 0.088646)
		(layer "In6.Cu")
		(net "M_C_CPU1_SB_DQS_DP<1>")
	)
	(segment
		(start 51.59883 -222.949262)
		(end 51.303682 -223.24441)
		(width 0.18288)
		(layer "In6.Cu")
		(net "M_C_CPU1_SB_DQS_DP<1>")
	)
	(segment
		(start 65.936622 -226.64039)
		(end 65.663064 -226.366832)
		(width 0.18288)
		(layer "In6.Cu")
		(net "M_C_CPU1_SB_DQS_DP<1>")
	)
	(segment
		(start 84.109814 -237.125002)
		(end 83.9597 -237.125002)
		(width 0.088646)
		(layer "In6.Cu")
		(net "M_C_CPU1_SB_DQS_DP<1>")
	)
	(segment
		(start 36.4871 -219.583762)
		(end 36.228528 -219.842334)
		(width 0.18288)
		(layer "In6.Cu")
		(net "M_C_CPU1_SB_DQS_DP<1>")
	)
	(segment
		(start 34.385504 -218.938856)
		(end 32.970724 -218.938856)
		(width 0.18288)
		(layer "In6.Cu")
		(net "M_C_CPU1_SB_DQS_DP<1>")
	)
	(segment
		(start 93.126814 -237.901226)
		(end 93.112082 -237.909862)
		(width 0.088646)
		(layer "In6.Cu")
		(net "M_C_CPU1_SB_DQS_DP<1>")
	)
	(segment
		(start 62.33287 -223.196658)
		(end 61.797692 -222.97517)
		(width 0.18288)
		(layer "In6.Cu")
		(net "M_C_CPU1_SB_DQS_DP<1>")
	)
	(segment
		(start 66.343276 -226.64039)
		(end 65.936622 -226.64039)
		(width 0.18288)
		(layer "In6.Cu")
		(net "M_C_CPU1_SB_DQS_DP<1>")
	)
	(segment
		(start 32.152336 -219.14104)
		(end 31.876746 -219.41663)
		(width 0.18288)
		(layer "In6.Cu")
		(net "M_C_CPU1_SB_DQS_DP<1>")
	)
	(segment
		(start 35.455098 -219.566236)
		(end 35.012884 -219.566236)
		(width 0.18288)
		(layer "In6.Cu")
		(net "M_C_CPU1_SB_DQS_DP<1>")
	)
	(segment
		(start 45.066204 -221.529656)
		(end 44.615354 -221.529656)
		(width 0.18288)
		(layer "In6.Cu")
		(net "M_C_CPU1_SB_DQS_DP<1>")
	)
	(segment
		(start 94.631764 -237.780576)
		(end 94.276164 -237.780576)
		(width 0.088646)
		(layer "In6.Cu")
		(net "M_C_CPU1_SB_DQS_DP<1>")
	)
	(segment
		(start 82.835496 -235.515912)
		(end 74.43343 -235.515912)
		(width 0.18288)
		(layer "In6.Cu")
		(net "M_C_CPU1_SB_DQS_DP<1>")
	)
	(segment
		(start 94.69374 -237.784894)
		(end 94.63659 -237.778036)
		(width 0.088646)
		(layer "In6.Cu")
		(net "M_C_CPU1_SB_DQS_DP<1>")
	)
	(segment
		(start 50.851562 -223.24441)
		(end 50.552858 -222.945706)
		(width 0.18288)
		(layer "In6.Cu")
		(net "M_C_CPU1_SB_DQS_DP<1>")
	)
	(segment
		(start 74.43343 -235.515912)
		(end 67.166236 -228.248718)
		(width 0.18288)
		(layer "In6.Cu")
		(net "M_C_CPU1_SB_DQS_DP<1>")
	)
	(segment
		(start 95.323406 -237.50143)
		(end 94.89821 -237.743238)
		(width 0.088646)
		(layer "In6.Cu")
		(net "M_C_CPU1_SB_DQS_DP<1>")
	)
	(segment
		(start 67.166236 -228.248718)
		(end 67.166236 -226.628452)
		(width 0.18288)
		(layer "In6.Cu")
		(net "M_C_CPU1_SB_DQS_DP<1>")
	)
	(segment
		(start 91.632278 -237.907322)
		(end 91.621864 -237.901226)
		(width 0.088646)
		(layer "In6.Cu")
		(net "M_C_CPU1_SB_DQS_DP<1>")
	)
	(segment
		(start 60.141104 -222.97517)
		(end 58.68924 -222.373698)
		(width 0.18288)
		(layer "In6.Cu")
		(net "M_C_CPU1_SB_DQS_DP<1>")
	)
	(segment
		(start 65.035176 -226.366832)
		(end 64.343788 -225.675444)
		(width 0.18288)
		(layer "In6.Cu")
		(net "M_C_CPU1_SB_DQS_DP<1>")
	)
	(segment
		(start 45.633894 -221.76486)
		(end 45.066204 -221.529656)
		(width 0.18288)
		(layer "In6.Cu")
		(net "M_C_CPU1_SB_DQS_DP<1>")
	)
	(segment
		(start 42.598848 -221.612714)
		(end 41.331642 -220.345)
		(width 0.18288)
		(layer "In6.Cu")
		(net "M_C_CPU1_SB_DQS_DP<1>")
	)
	(segment
		(start 83.50123 -236.666532)
		(end 83.50123 -236.318552)
		(width 0.088646)
		(layer "In6.Cu")
		(net "M_C_CPU1_SB_DQS_DP<1>")
	)
	(segment
		(start 83.9597 -237.125002)
		(end 83.50123 -236.666532)
		(width 0.088646)
		(layer "In6.Cu")
		(net "M_C_CPU1_SB_DQS_DP<1>")
	)
	(segment
		(start 67.166236 -226.628452)
		(end 66.894202 -226.356418)
		(width 0.18288)
		(layer "In6.Cu")
		(net "M_C_CPU1_SB_DQS_DP<1>")
	)
	(segment
		(start 45.985176 -222.116142)
		(end 45.633894 -221.76486)
		(width 0.18288)
		(layer "In6.Cu")
		(net "M_C_CPU1_SB_DQS_DP<1>")
	)
	(segment
		(start 47.22495 -222.39351)
		(end 46.730158 -222.39351)
		(width 0.18288)
		(layer "In6.Cu")
		(net "M_C_CPU1_SB_DQS_DP<1>")
	)
	(segment
		(start 51.303682 -223.24441)
		(end 50.851562 -223.24441)
		(width 0.18288)
		(layer "In6.Cu")
		(net "M_C_CPU1_SB_DQS_DP<1>")
	)
	(segment
		(start 43.209718 -221.865952)
		(end 42.598848 -221.612714)
		(width 0.18288)
		(layer "In6.Cu")
		(net "M_C_CPU1_SB_DQS_DP<1>")
	)
	(segment
		(start 89.367614 -237.901226)
		(end 89.352882 -237.909862)
		(width 0.088646)
		(layer "In6.Cu")
		(net "M_C_CPU1_SB_DQS_DP<1>")
	)
	(segment
		(start 50.552858 -222.945706)
		(end 50.127916 -222.945706)
		(width 0.18288)
		(layer "In6.Cu")
		(net "M_C_CPU1_SB_DQS_DP<1>")
	)
	(segment
		(start 32.482282 -219.14104)
		(end 32.152336 -219.14104)
		(width 0.18288)
		(layer "In6.Cu")
		(net "M_C_CPU1_SB_DQS_DP<1>")
	)
	(segment
		(start 90.307414 -237.901226)
		(end 90.292682 -237.909862)
		(width 0.088646)
		(layer "In6.Cu")
		(net "M_C_CPU1_SB_DQS_DP<1>")
	)
	(segment
		(start 49.31537 -222.132652)
		(end 47.485808 -222.132652)
		(width 0.18288)
		(layer "In6.Cu")
		(net "M_C_CPU1_SB_DQS_DP<1>")
	)
	(segment
		(start 63.337186 -225.07575)
		(end 62.33287 -223.196658)
		(width 0.18288)
		(layer "In6.Cu")
		(net "M_C_CPU1_SB_DQS_DP<1>")
	)
	(segment
		(start 94.63659 -237.778036)
		(end 94.631764 -237.780576)
		(width 0.088646)
		(layer "In6.Cu")
		(net "M_C_CPU1_SB_DQS_DP<1>")
	)
	(segment
		(start 58.68924 -222.373698)
		(end 55.343298 -222.373698)
		(width 0.18288)
		(layer "In6.Cu")
		(net "M_C_CPU1_SB_DQS_DP<1>")
	)
	(segment
		(start 46.730158 -222.39351)
		(end 46.45279 -222.116142)
		(width 0.18288)
		(layer "In6.Cu")
		(net "M_C_CPU1_SB_DQS_DP<1>")
	)
	(segment
		(start 50.127916 -222.945706)
		(end 49.31537 -222.132652)
		(width 0.18288)
		(layer "In6.Cu")
		(net "M_C_CPU1_SB_DQS_DP<1>")
	)
	(segment
		(start 44.615354 -221.529656)
		(end 43.803316 -221.865952)
		(width 0.18288)
		(layer "In6.Cu")
		(net "M_C_CPU1_SB_DQS_DP<1>")
	)
	(segment
		(start 85.138514 -237.08741)
		(end 85.123782 -237.096046)
		(width 0.088646)
		(layer "In6.Cu")
		(net "M_C_CPU1_SB_DQS_DP<1>")
	)
	(segment
		(start 36.228528 -219.842334)
		(end 35.731196 -219.842334)
		(width 0.18288)
		(layer "In6.Cu")
		(net "M_C_CPU1_SB_DQS_DP<1>")
	)
	(segment
		(start 64.343788 -225.675444)
		(end 63.649098 -225.387662)
		(width 0.18288)
		(layer "In6.Cu")
		(net "M_C_CPU1_SB_DQS_DP<1>")
	)
	(segment
		(start 43.803316 -221.865952)
		(end 43.209718 -221.865952)
		(width 0.18288)
		(layer "In6.Cu")
		(net "M_C_CPU1_SB_DQS_DP<1>")
	)
	(segment
		(start 65.663064 -226.366832)
		(end 65.035176 -226.366832)
		(width 0.18288)
		(layer "In6.Cu")
		(net "M_C_CPU1_SB_DQS_DP<1>")
	)
	(segment
		(start 39.49573 -219.583762)
		(end 36.4871 -219.583762)
		(width 0.18288)
		(layer "In6.Cu")
		(net "M_C_CPU1_SB_DQS_DP<1>")
	)
	(segment
		(start 83.095592 -235.455968)
		(end 82.918808 -235.455968)
		(width 0.088646)
		(layer "In6.Cu")
		(net "M_C_CPU1_SB_DQS_DP<1>")
	)
	(segment
		(start 83.50123 -236.318552)
		(end 83.422236 -236.239558)
		(width 0.088646)
		(layer "In6.Cu")
		(net "M_C_CPU1_SB_DQS_DP<1>")
	)
	(segment
		(start 66.627248 -226.356418)
		(end 66.343276 -226.64039)
		(width 0.18288)
		(layer "In6.Cu")
		(net "M_C_CPU1_SB_DQS_DP<1>")
	)
	(segment
		(start 82.918808 -235.455968)
		(end 82.858864 -235.515912)
		(width 0.088646)
		(layer "In6.Cu")
		(net "M_C_CPU1_SB_DQS_DP<1>")
	)
	(segment
		(start 66.894202 -226.356418)
		(end 66.627248 -226.356418)
		(width 0.18288)
		(layer "In6.Cu")
		(net "M_C_CPU1_SB_DQS_DP<1>")
	)
	(segment
		(start 61.797692 -222.97517)
		(end 60.141104 -222.97517)
		(width 0.18288)
		(layer "In6.Cu")
		(net "M_C_CPU1_SB_DQS_DP<1>")
	)
	(segment
		(start 32.970724 -218.938856)
		(end 32.482282 -219.14104)
		(width 0.18288)
		(layer "In6.Cu")
		(net "M_C_CPU1_SB_DQS_DP<1>")
	)
	(segment
		(start 82.858864 -235.515912)
		(end 82.835496 -235.515912)
		(width 0.088646)
		(layer "In6.Cu")
		(net "M_C_CPU1_SB_DQS_DP<1>")
	)
	(segment
		(start 88.427814 -237.901226)
		(end 88.4174 -237.907322)
		(width 0.088646)
		(layer "In6.Cu")
		(net "M_C_CPU1_SB_DQS_DP<1>")
	)
	(segment
		(start 35.012884 -219.566236)
		(end 34.385504 -218.938856)
		(width 0.18288)
		(layer "In6.Cu")
		(net "M_C_CPU1_SB_DQS_DP<1>")
	)
	(segment
		(start 83.422236 -236.239558)
		(end 83.422236 -235.782612)
		(width 0.088646)
		(layer "In6.Cu")
		(net "M_C_CPU1_SB_DQS_DP<1>")
	)
	(segment
		(start 86.933024 -237.907322)
		(end 86.92261 -237.901226)
		(width 0.088646)
		(layer "In6.Cu")
		(net "M_C_CPU1_SB_DQS_DP<1>")
	)
	(segment
		(start 94.276164 -237.780576)
		(end 94.052644 -237.909354)
		(width 0.088646)
		(layer "In6.Cu")
		(net "M_C_CPU1_SB_DQS_DP<1>")
	)
	(segment
		(start 91.247468 -237.901226)
		(end 91.237054 -237.907322)
		(width 0.088646)
		(layer "In6.Cu")
		(net "M_C_CPU1_SB_DQS_DP<1>")
	)
	(segment
		(start 41.331642 -220.345)
		(end 39.49573 -219.583762)
		(width 0.18288)
		(layer "In6.Cu")
		(net "M_C_CPU1_SB_DQS_DP<1>")
	)
	(arc
		(start 87.488268 -237.901226)
		(mid 87.211455 -237.977096)
		(end 86.933024 -237.907322)
		(width 0.088646)
		(layer "In6.Cu")
		(net "M_C_CPU1_SB_DQS_DP<1>")
	)
	(arc
		(start 85.700362 -237.411768)
		(mid 85.513063 -237.087327)
		(end 85.138514 -237.08741)
		(width 0.088646)
		(layer "In6.Cu")
		(net "M_C_CPU1_SB_DQS_DP<1>")
	)
	(arc
		(start 86.548214 -237.901226)
		(mid 85.982937 -237.9013)
		(end 85.700362 -237.411768)
		(width 0.088646)
		(layer "In6.Cu")
		(net "M_C_CPU1_SB_DQS_DP<1>")
	)
	(arc
		(start 87.862664 -237.901226)
		(mid 87.675466 -237.851083)
		(end 87.488268 -237.901226)
		(width 0.088646)
		(layer "In6.Cu")
		(net "M_C_CPU1_SB_DQS_DP<1>")
	)
	(arc
		(start 85.123782 -237.096046)
		(mid 84.847307 -237.163366)
		(end 84.57311 -237.08741)
		(width 0.088646)
		(layer "In6.Cu")
		(net "M_C_CPU1_SB_DQS_DP<1>")
	)
	(arc
		(start 90.292682 -237.909862)
		(mid 90.016207 -237.977182)
		(end 89.74201 -237.901226)
		(width 0.088646)
		(layer "In6.Cu")
		(net "M_C_CPU1_SB_DQS_DP<1>")
	)
	(arc
		(start 95.663766 -237.411514)
		(mid 95.487745 -237.434351)
		(end 95.323406 -237.50143)
		(width 0.088646)
		(layer "In6.Cu")
		(net "M_C_CPU1_SB_DQS_DP<1>")
	)
	(arc
		(start 88.4174 -237.907322)
		(mid 88.139222 -237.977014)
		(end 87.862664 -237.901226)
		(width 0.088646)
		(layer "In6.Cu")
		(net "M_C_CPU1_SB_DQS_DP<1>")
	)
	(arc
		(start 90.68181 -237.901226)
		(mid 90.494612 -237.851083)
		(end 90.307414 -237.901226)
		(width 0.088646)
		(layer "In6.Cu")
		(net "M_C_CPU1_SB_DQS_DP<1>")
	)
	(arc
		(start 91.621864 -237.901226)
		(mid 91.434666 -237.851083)
		(end 91.247468 -237.901226)
		(width 0.088646)
		(layer "In6.Cu")
		(net "M_C_CPU1_SB_DQS_DP<1>")
	)
	(arc
		(start 89.74201 -237.901226)
		(mid 89.554812 -237.851083)
		(end 89.367614 -237.901226)
		(width 0.088646)
		(layer "In6.Cu")
		(net "M_C_CPU1_SB_DQS_DP<1>")
	)
	(arc
		(start 84.57311 -237.08741)
		(mid 84.390007 -237.037289)
		(end 84.205826 -237.083346)
		(width 0.088646)
		(layer "In6.Cu")
		(net "M_C_CPU1_SB_DQS_DP<1>")
	)
	(arc
		(start 93.112082 -237.909862)
		(mid 92.835641 -237.977028)
		(end 92.56141 -237.901226)
		(width 0.088646)
		(layer "In6.Cu")
		(net "M_C_CPU1_SB_DQS_DP<1>")
	)
	(arc
		(start 92.56141 -237.901226)
		(mid 92.374212 -237.851083)
		(end 92.187014 -237.901226)
		(width 0.088646)
		(layer "In6.Cu")
		(net "M_C_CPU1_SB_DQS_DP<1>")
	)
	(arc
		(start 89.352882 -237.909862)
		(mid 89.076441 -237.977028)
		(end 88.80221 -237.901226)
		(width 0.088646)
		(layer "In6.Cu")
		(net "M_C_CPU1_SB_DQS_DP<1>")
	)
	(arc
		(start 93.50121 -237.901226)
		(mid 93.314012 -237.851083)
		(end 93.126814 -237.901226)
		(width 0.088646)
		(layer "In6.Cu")
		(net "M_C_CPU1_SB_DQS_DP<1>")
	)
	(arc
		(start 92.187014 -237.901226)
		(mid 91.910455 -237.976969)
		(end 91.632278 -237.907322)
		(width 0.088646)
		(layer "In6.Cu")
		(net "M_C_CPU1_SB_DQS_DP<1>")
	)
	(arc
		(start 88.80221 -237.901226)
		(mid 88.615012 -237.851083)
		(end 88.427814 -237.901226)
		(width 0.088646)
		(layer "In6.Cu")
		(net "M_C_CPU1_SB_DQS_DP<1>")
	)
	(arc
		(start 86.92261 -237.901226)
		(mid 86.735412 -237.851083)
		(end 86.548214 -237.901226)
		(width 0.088646)
		(layer "In6.Cu")
		(net "M_C_CPU1_SB_DQS_DP<1>")
	)
	(arc
		(start 84.205826 -237.083346)
		(mid 84.158786 -237.1064)
		(end 84.109814 -237.125002)
		(width 0.088646)
		(layer "In6.Cu")
		(net "M_C_CPU1_SB_DQS_DP<1>")
	)
	(arc
		(start 91.237054 -237.907322)
		(mid 90.958622 -237.977168)
		(end 90.68181 -237.901226)
		(width 0.088646)
		(layer "In6.Cu")
		(net "M_C_CPU1_SB_DQS_DP<1>")
	)
	(arc
		(start 94.052644 -237.909354)
		(mid 93.775979 -237.976825)
		(end 93.501464 -237.900972)
		(width 0.088646)
		(layer "In6.Cu")
		(net "M_C_CPU1_SB_DQS_DP<1>")
	)
	(arc
		(start 94.89821 -237.743238)
		(mid 94.799368 -237.780748)
		(end 94.69374 -237.784894)
		(width 0.088646)
		(layer "In6.Cu")
		(net "M_C_CPU1_SB_DQS_DP<1>")
	)
	(segment
		(start 28.52928 -229.19182)
		(end 28.681172 -229.19182)
		(width 0.20066)
		(layer "F.Cu")
		(net "M_C_CPU1_SB_DQS_DP<0>")
	)
	(segment
		(start 26.20391 -229.201218)
		(end 26.204164 -229.200964)
		(width 0.20066)
		(layer "F.Cu")
		(net "M_C_CPU1_SB_DQS_DP<0>")
	)
	(segment
		(start 26.204164 -229.200964)
		(end 26.213308 -229.19182)
		(width 0.101854)
		(layer "F.Cu")
		(net "M_C_CPU1_SB_DQS_DP<0>")
	)
	(segment
		(start 29.693362 -228.505512)
		(end 29.962094 -228.505512)
		(width 0.20066)
		(layer "F.Cu")
		(net "M_C_CPU1_SB_DQS_DP<0>")
	)
	(segment
		(start 28.942284 -228.930708)
		(end 29.268166 -228.930708)
		(width 0.20066)
		(layer "F.Cu")
		(net "M_C_CPU1_SB_DQS_DP<0>")
	)
	(segment
		(start 26.45029 -229.19182)
		(end 28.205684 -229.19182)
		(width 0.1016)
		(layer "F.Cu")
		(net "M_C_CPU1_SB_DQS_DP<0>")
	)
	(segment
		(start 28.205684 -229.19182)
		(end 28.52928 -229.19182)
		(width 0.101854)
		(layer "F.Cu")
		(net "M_C_CPU1_SB_DQS_DP<0>")
	)
	(segment
		(start 24.02713 -228.505512)
		(end 24.452834 -228.505512)
		(width 0.20066)
		(layer "F.Cu")
		(net "M_C_CPU1_SB_DQS_DP<0>")
	)
	(segment
		(start 28.681172 -229.19182)
		(end 28.942284 -228.930708)
		(width 0.20066)
		(layer "F.Cu")
		(net "M_C_CPU1_SB_DQS_DP<0>")
	)
	(segment
		(start 26.213308 -229.19182)
		(end 26.45029 -229.19182)
		(width 0.101854)
		(layer "F.Cu")
		(net "M_C_CPU1_SB_DQS_DP<0>")
	)
	(segment
		(start 30.223206 -228.766624)
		(end 30.771846 -228.766624)
		(width 0.20066)
		(layer "F.Cu")
		(net "M_C_CPU1_SB_DQS_DP<0>")
	)
	(segment
		(start 23.228046 -228.766624)
		(end 23.766018 -228.766624)
		(width 0.20066)
		(layer "F.Cu")
		(net "M_C_CPU1_SB_DQS_DP<0>")
	)
	(segment
		(start 23.766018 -228.766624)
		(end 24.02713 -228.505512)
		(width 0.20066)
		(layer "F.Cu")
		(net "M_C_CPU1_SB_DQS_DP<0>")
	)
	(segment
		(start 25.087834 -228.930708)
		(end 25.715214 -228.930708)
		(width 0.20066)
		(layer "F.Cu")
		(net "M_C_CPU1_SB_DQS_DP<0>")
	)
	(segment
		(start 95.663512 -242.830858)
		(end 95.663766 -242.294918)
		(width 0.20066)
		(layer "F.Cu")
		(net "M_C_CPU1_SB_DQS_DP<0>")
	)
	(segment
		(start 24.452834 -228.505512)
		(end 25.087834 -228.930708)
		(width 0.20066)
		(layer "F.Cu")
		(net "M_C_CPU1_SB_DQS_DP<0>")
	)
	(segment
		(start 25.985724 -229.201218)
		(end 26.20391 -229.201218)
		(width 0.20066)
		(layer "F.Cu")
		(net "M_C_CPU1_SB_DQS_DP<0>")
	)
	(segment
		(start 29.962094 -228.505512)
		(end 30.223206 -228.766624)
		(width 0.20066)
		(layer "F.Cu")
		(net "M_C_CPU1_SB_DQS_DP<0>")
	)
	(segment
		(start 25.715214 -228.930708)
		(end 25.985724 -229.201218)
		(width 0.20066)
		(layer "F.Cu")
		(net "M_C_CPU1_SB_DQS_DP<0>")
	)
	(segment
		(start 29.268166 -228.930708)
		(end 29.693362 -228.505512)
		(width 0.20066)
		(layer "F.Cu")
		(net "M_C_CPU1_SB_DQS_DP<0>")
	)
	(segment
		(start 31.876746 -228.766624)
		(end 30.771846 -228.766624)
		(width 0.20066)
		(layer "F.Cu")
		(net "M_C_CPU1_SB_DQS_DP<0>")
	)
	(segment
		(start 62.141354 -235.749846)
		(end 59.767216 -235.749846)
		(width 0.18288)
		(layer "In6.Cu")
		(net "M_C_CPU1_SB_DQS_DP<0>")
	)
	(segment
		(start 50.580798 -234.005882)
		(end 50.143156 -234.005882)
		(width 0.18288)
		(layer "In6.Cu")
		(net "M_C_CPU1_SB_DQS_DP<0>")
	)
	(segment
		(start 35.778694 -229.191566)
		(end 35.493198 -228.90607)
		(width 0.18288)
		(layer "In6.Cu")
		(net "M_C_CPU1_SB_DQS_DP<0>")
	)
	(segment
		(start 94.69374 -242.668298)
		(end 94.63659 -242.66144)
		(width 0.088646)
		(layer "In6.Cu")
		(net "M_C_CPU1_SB_DQS_DP<0>")
	)
	(segment
		(start 91.632278 -242.790726)
		(end 91.621864 -242.78463)
		(width 0.088646)
		(layer "In6.Cu")
		(net "M_C_CPU1_SB_DQS_DP<0>")
	)
	(segment
		(start 51.614324 -234.021884)
		(end 51.344576 -234.291632)
		(width 0.18288)
		(layer "In6.Cu")
		(net "M_C_CPU1_SB_DQS_DP<0>")
	)
	(segment
		(start 91.247468 -242.78463)
		(end 91.237054 -242.790726)
		(width 0.088646)
		(layer "In6.Cu")
		(net "M_C_CPU1_SB_DQS_DP<0>")
	)
	(segment
		(start 88.427814 -242.78463)
		(end 88.4174 -242.790726)
		(width 0.088646)
		(layer "In6.Cu")
		(net "M_C_CPU1_SB_DQS_DP<0>")
	)
	(segment
		(start 83.342988 -241.376708)
		(end 83.172808 -241.376708)
		(width 0.088646)
		(layer "In6.Cu")
		(net "M_C_CPU1_SB_DQS_DP<0>")
	)
	(segment
		(start 47.48784 -233.170476)
		(end 47.216568 -233.441748)
		(width 0.18288)
		(layer "In6.Cu")
		(net "M_C_CPU1_SB_DQS_DP<0>")
	)
	(segment
		(start 55.516018 -234.751118)
		(end 54.786784 -234.021884)
		(width 0.18288)
		(layer "In6.Cu")
		(net "M_C_CPU1_SB_DQS_DP<0>")
	)
	(segment
		(start 32.673798 -228.485192)
		(end 32.158178 -228.485192)
		(width 0.18288)
		(layer "In6.Cu")
		(net "M_C_CPU1_SB_DQS_DP<0>")
	)
	(segment
		(start 90.307414 -242.78463)
		(end 90.292682 -242.793266)
		(width 0.088646)
		(layer "In6.Cu")
		(net "M_C_CPU1_SB_DQS_DP<0>")
	)
	(segment
		(start 94.63659 -242.66144)
		(end 94.631764 -242.66398)
		(width 0.088646)
		(layer "In6.Cu")
		(net "M_C_CPU1_SB_DQS_DP<0>")
	)
	(segment
		(start 93.126814 -242.78463)
		(end 93.112082 -242.793266)
		(width 0.088646)
		(layer "In6.Cu")
		(net "M_C_CPU1_SB_DQS_DP<0>")
	)
	(segment
		(start 42.602658 -231.207818)
		(end 40.814752 -231.207818)
		(width 0.18288)
		(layer "In6.Cu")
		(net "M_C_CPU1_SB_DQS_DP<0>")
	)
	(segment
		(start 33.291272 -228.229414)
		(end 32.673798 -228.485192)
		(width 0.18288)
		(layer "In6.Cu")
		(net "M_C_CPU1_SB_DQS_DP<0>")
	)
	(segment
		(start 35.493198 -228.90607)
		(end 34.890456 -228.90607)
		(width 0.18288)
		(layer "In6.Cu")
		(net "M_C_CPU1_SB_DQS_DP<0>")
	)
	(segment
		(start 51.344576 -234.291632)
		(end 50.866548 -234.291632)
		(width 0.18288)
		(layer "In6.Cu")
		(net "M_C_CPU1_SB_DQS_DP<0>")
	)
	(segment
		(start 59.767216 -235.749846)
		(end 58.768488 -234.751118)
		(width 0.18288)
		(layer "In6.Cu")
		(net "M_C_CPU1_SB_DQS_DP<0>")
	)
	(segment
		(start 71.286624 -241.436652)
		(end 67.004946 -237.154974)
		(width 0.18288)
		(layer "In6.Cu")
		(net "M_C_CPU1_SB_DQS_DP<0>")
	)
	(segment
		(start 45.527976 -233.155998)
		(end 44.271946 -231.899968)
		(width 0.18288)
		(layer "In6.Cu")
		(net "M_C_CPU1_SB_DQS_DP<0>")
	)
	(segment
		(start 38.747192 -230.356918)
		(end 37.302186 -228.911912)
		(width 0.18288)
		(layer "In6.Cu")
		(net "M_C_CPU1_SB_DQS_DP<0>")
	)
	(segment
		(start 37.302186 -228.911912)
		(end 36.536884 -228.911912)
		(width 0.18288)
		(layer "In6.Cu")
		(net "M_C_CPU1_SB_DQS_DP<0>")
	)
	(segment
		(start 36.25723 -229.191566)
		(end 35.778694 -229.191566)
		(width 0.18288)
		(layer "In6.Cu")
		(net "M_C_CPU1_SB_DQS_DP<0>")
	)
	(segment
		(start 39.963852 -230.356918)
		(end 38.747192 -230.356918)
		(width 0.18288)
		(layer "In6.Cu")
		(net "M_C_CPU1_SB_DQS_DP<0>")
	)
	(segment
		(start 49.30775 -233.170476)
		(end 47.48784 -233.170476)
		(width 0.18288)
		(layer "In6.Cu")
		(net "M_C_CPU1_SB_DQS_DP<0>")
	)
	(segment
		(start 94.276164 -242.66398)
		(end 94.052644 -242.792758)
		(width 0.088646)
		(layer "In6.Cu")
		(net "M_C_CPU1_SB_DQS_DP<0>")
	)
	(segment
		(start 63.612014 -236.360462)
		(end 62.141354 -235.749846)
		(width 0.18288)
		(layer "In6.Cu")
		(net "M_C_CPU1_SB_DQS_DP<0>")
	)
	(segment
		(start 83.813904 -242.522502)
		(end 83.813904 -241.847624)
		(width 0.088646)
		(layer "In6.Cu")
		(net "M_C_CPU1_SB_DQS_DP<0>")
	)
	(segment
		(start 83.813904 -241.847624)
		(end 83.342988 -241.376708)
		(width 0.088646)
		(layer "In6.Cu")
		(net "M_C_CPU1_SB_DQS_DP<0>")
	)
	(segment
		(start 94.631764 -242.66398)
		(end 94.276164 -242.66398)
		(width 0.088646)
		(layer "In6.Cu")
		(net "M_C_CPU1_SB_DQS_DP<0>")
	)
	(segment
		(start 46.45279 -233.155998)
		(end 45.527976 -233.155998)
		(width 0.18288)
		(layer "In6.Cu")
		(net "M_C_CPU1_SB_DQS_DP<0>")
	)
	(segment
		(start 32.158178 -228.485192)
		(end 31.876746 -228.766624)
		(width 0.18288)
		(layer "In6.Cu")
		(net "M_C_CPU1_SB_DQS_DP<0>")
	)
	(segment
		(start 46.73854 -233.441748)
		(end 46.45279 -233.155998)
		(width 0.18288)
		(layer "In6.Cu")
		(net "M_C_CPU1_SB_DQS_DP<0>")
	)
	(segment
		(start 50.866548 -234.291632)
		(end 50.580798 -234.005882)
		(width 0.18288)
		(layer "In6.Cu")
		(net "M_C_CPU1_SB_DQS_DP<0>")
	)
	(segment
		(start 83.112864 -241.436652)
		(end 83.089496 -241.436652)
		(width 0.088646)
		(layer "In6.Cu")
		(net "M_C_CPU1_SB_DQS_DP<0>")
	)
	(segment
		(start 83.089496 -241.436652)
		(end 71.286624 -241.436652)
		(width 0.18288)
		(layer "In6.Cu")
		(net "M_C_CPU1_SB_DQS_DP<0>")
	)
	(segment
		(start 34.890456 -228.90607)
		(end 34.42843 -228.444044)
		(width 0.18288)
		(layer "In6.Cu")
		(net "M_C_CPU1_SB_DQS_DP<0>")
	)
	(segment
		(start 93.501464 -242.784376)
		(end 93.50121 -242.78463)
		(width 0.088646)
		(layer "In6.Cu")
		(net "M_C_CPU1_SB_DQS_DP<0>")
	)
	(segment
		(start 36.536884 -228.911912)
		(end 36.25723 -229.191566)
		(width 0.18288)
		(layer "In6.Cu")
		(net "M_C_CPU1_SB_DQS_DP<0>")
	)
	(segment
		(start 83.986116 -242.694714)
		(end 83.813904 -242.522502)
		(width 0.088646)
		(layer "In6.Cu")
		(net "M_C_CPU1_SB_DQS_DP<0>")
	)
	(segment
		(start 64.578992 -236.360462)
		(end 63.612014 -236.360462)
		(width 0.18288)
		(layer "In6.Cu")
		(net "M_C_CPU1_SB_DQS_DP<0>")
	)
	(segment
		(start 47.216568 -233.441748)
		(end 46.73854 -233.441748)
		(width 0.18288)
		(layer "In6.Cu")
		(net "M_C_CPU1_SB_DQS_DP<0>")
	)
	(segment
		(start 40.814752 -231.207818)
		(end 39.963852 -230.356918)
		(width 0.18288)
		(layer "In6.Cu")
		(net "M_C_CPU1_SB_DQS_DP<0>")
	)
	(segment
		(start 65.373504 -237.154974)
		(end 64.578992 -236.360462)
		(width 0.18288)
		(layer "In6.Cu")
		(net "M_C_CPU1_SB_DQS_DP<0>")
	)
	(segment
		(start 89.367614 -242.78463)
		(end 89.352882 -242.793266)
		(width 0.088646)
		(layer "In6.Cu")
		(net "M_C_CPU1_SB_DQS_DP<0>")
	)
	(segment
		(start 95.323406 -242.384834)
		(end 94.89821 -242.626642)
		(width 0.088646)
		(layer "In6.Cu")
		(net "M_C_CPU1_SB_DQS_DP<0>")
	)
	(segment
		(start 33.91027 -228.229414)
		(end 33.291272 -228.229414)
		(width 0.18288)
		(layer "In6.Cu")
		(net "M_C_CPU1_SB_DQS_DP<0>")
	)
	(segment
		(start 67.004946 -237.154974)
		(end 65.373504 -237.154974)
		(width 0.18288)
		(layer "In6.Cu")
		(net "M_C_CPU1_SB_DQS_DP<0>")
	)
	(segment
		(start 50.143156 -234.005882)
		(end 49.30775 -233.170476)
		(width 0.18288)
		(layer "In6.Cu")
		(net "M_C_CPU1_SB_DQS_DP<0>")
	)
	(segment
		(start 54.786784 -234.021884)
		(end 51.614324 -234.021884)
		(width 0.18288)
		(layer "In6.Cu")
		(net "M_C_CPU1_SB_DQS_DP<0>")
	)
	(segment
		(start 83.172808 -241.376708)
		(end 83.112864 -241.436652)
		(width 0.088646)
		(layer "In6.Cu")
		(net "M_C_CPU1_SB_DQS_DP<0>")
	)
	(segment
		(start 34.42843 -228.444044)
		(end 33.91027 -228.229414)
		(width 0.18288)
		(layer "In6.Cu")
		(net "M_C_CPU1_SB_DQS_DP<0>")
	)
	(segment
		(start 85.057996 -242.793266)
		(end 85.043264 -242.78463)
		(width 0.088646)
		(layer "In6.Cu")
		(net "M_C_CPU1_SB_DQS_DP<0>")
	)
	(segment
		(start 86.937596 -242.793266)
		(end 86.922864 -242.78463)
		(width 0.088646)
		(layer "In6.Cu")
		(net "M_C_CPU1_SB_DQS_DP<0>")
	)
	(segment
		(start 58.768488 -234.751118)
		(end 55.516018 -234.751118)
		(width 0.18288)
		(layer "In6.Cu")
		(net "M_C_CPU1_SB_DQS_DP<0>")
	)
	(segment
		(start 44.271946 -231.899968)
		(end 42.602658 -231.207818)
		(width 0.18288)
		(layer "In6.Cu")
		(net "M_C_CPU1_SB_DQS_DP<0>")
	)
	(arc
		(start 85.983064 -242.78463)
		(mid 85.795866 -242.734487)
		(end 85.608668 -242.78463)
		(width 0.088646)
		(layer "In6.Cu")
		(net "M_C_CPU1_SB_DQS_DP<0>")
	)
	(arc
		(start 95.663766 -242.294918)
		(mid 95.487745 -242.317755)
		(end 95.323406 -242.384834)
		(width 0.088646)
		(layer "In6.Cu")
		(net "M_C_CPU1_SB_DQS_DP<0>")
	)
	(arc
		(start 85.043264 -242.78463)
		(mid 84.856066 -242.734487)
		(end 84.668868 -242.78463)
		(width 0.088646)
		(layer "In6.Cu")
		(net "M_C_CPU1_SB_DQS_DP<0>")
	)
	(arc
		(start 94.89821 -242.626642)
		(mid 94.799368 -242.664152)
		(end 94.69374 -242.668298)
		(width 0.088646)
		(layer "In6.Cu")
		(net "M_C_CPU1_SB_DQS_DP<0>")
	)
	(arc
		(start 89.74201 -242.78463)
		(mid 89.554812 -242.734487)
		(end 89.367614 -242.78463)
		(width 0.088646)
		(layer "In6.Cu")
		(net "M_C_CPU1_SB_DQS_DP<0>")
	)
	(arc
		(start 92.56141 -242.78463)
		(mid 92.374212 -242.734487)
		(end 92.187014 -242.78463)
		(width 0.088646)
		(layer "In6.Cu")
		(net "M_C_CPU1_SB_DQS_DP<0>")
	)
	(arc
		(start 85.608668 -242.78463)
		(mid 85.334439 -242.860555)
		(end 85.057996 -242.793266)
		(width 0.088646)
		(layer "In6.Cu")
		(net "M_C_CPU1_SB_DQS_DP<0>")
	)
	(arc
		(start 94.052644 -242.792758)
		(mid 93.775979 -242.860229)
		(end 93.501464 -242.784376)
		(width 0.088646)
		(layer "In6.Cu")
		(net "M_C_CPU1_SB_DQS_DP<0>")
	)
	(arc
		(start 86.548468 -242.78463)
		(mid 86.265766 -242.860372)
		(end 85.983064 -242.78463)
		(width 0.088646)
		(layer "In6.Cu")
		(net "M_C_CPU1_SB_DQS_DP<0>")
	)
	(arc
		(start 91.237054 -242.790726)
		(mid 90.958622 -242.860572)
		(end 90.68181 -242.78463)
		(width 0.088646)
		(layer "In6.Cu")
		(net "M_C_CPU1_SB_DQS_DP<0>")
	)
	(arc
		(start 86.922864 -242.78463)
		(mid 86.735666 -242.734487)
		(end 86.548468 -242.78463)
		(width 0.088646)
		(layer "In6.Cu")
		(net "M_C_CPU1_SB_DQS_DP<0>")
	)
	(arc
		(start 93.50121 -242.78463)
		(mid 93.314012 -242.734487)
		(end 93.126814 -242.78463)
		(width 0.088646)
		(layer "In6.Cu")
		(net "M_C_CPU1_SB_DQS_DP<0>")
	)
	(arc
		(start 91.621864 -242.78463)
		(mid 91.434666 -242.734487)
		(end 91.247468 -242.78463)
		(width 0.088646)
		(layer "In6.Cu")
		(net "M_C_CPU1_SB_DQS_DP<0>")
	)
	(arc
		(start 93.112082 -242.793266)
		(mid 92.835641 -242.860432)
		(end 92.56141 -242.78463)
		(width 0.088646)
		(layer "In6.Cu")
		(net "M_C_CPU1_SB_DQS_DP<0>")
	)
	(arc
		(start 92.187014 -242.78463)
		(mid 91.910455 -242.860373)
		(end 91.632278 -242.790726)
		(width 0.088646)
		(layer "In6.Cu")
		(net "M_C_CPU1_SB_DQS_DP<0>")
	)
	(arc
		(start 87.488268 -242.78463)
		(mid 87.214039 -242.860555)
		(end 86.937596 -242.793266)
		(width 0.088646)
		(layer "In6.Cu")
		(net "M_C_CPU1_SB_DQS_DP<0>")
	)
	(arc
		(start 89.352882 -242.793266)
		(mid 89.076407 -242.860586)
		(end 88.80221 -242.78463)
		(width 0.088646)
		(layer "In6.Cu")
		(net "M_C_CPU1_SB_DQS_DP<0>")
	)
	(arc
		(start 90.68181 -242.78463)
		(mid 90.494612 -242.734487)
		(end 90.307414 -242.78463)
		(width 0.088646)
		(layer "In6.Cu")
		(net "M_C_CPU1_SB_DQS_DP<0>")
	)
	(arc
		(start 88.80221 -242.78463)
		(mid 88.615012 -242.734487)
		(end 88.427814 -242.78463)
		(width 0.088646)
		(layer "In6.Cu")
		(net "M_C_CPU1_SB_DQS_DP<0>")
	)
	(arc
		(start 84.668868 -242.78463)
		(mid 84.312256 -242.855521)
		(end 83.986116 -242.694714)
		(width 0.088646)
		(layer "In6.Cu")
		(net "M_C_CPU1_SB_DQS_DP<0>")
	)
	(arc
		(start 88.4174 -242.790726)
		(mid 88.139222 -242.860449)
		(end 87.862664 -242.78463)
		(width 0.088646)
		(layer "In6.Cu")
		(net "M_C_CPU1_SB_DQS_DP<0>")
	)
	(arc
		(start 90.292682 -242.793266)
		(mid 90.016207 -242.860586)
		(end 89.74201 -242.78463)
		(width 0.088646)
		(layer "In6.Cu")
		(net "M_C_CPU1_SB_DQS_DP<0>")
	)
	(arc
		(start 87.862664 -242.78463)
		(mid 87.675466 -242.734487)
		(end 87.488268 -242.78463)
		(width 0.088646)
		(layer "In6.Cu")
		(net "M_C_CPU1_SB_DQS_DP<0>")
	)
	(segment
		(start 91.434666 -239.85347)
		(end 91.434412 -239.853216)
		(width 0.20066)
		(layer "F.Cu")
		(net "M_C_CPU1_SB_DQS_DN<9>")
	)
	(segment
		(start 26.21534 -237.691676)
		(end 28.529026 -237.691676)
		(width 0.1016)
		(layer "F.Cu")
		(net "M_C_CPU1_SB_DQS_DN<9>")
	)
	(segment
		(start 29.964126 -237.527846)
		(end 30.225238 -237.266734)
		(width 0.20066)
		(layer "F.Cu")
		(net "M_C_CPU1_SB_DQS_DN<9>")
	)
	(segment
		(start 25.738328 -237.953042)
		(end 25.999694 -237.691676)
		(width 0.20066)
		(layer "F.Cu")
		(net "M_C_CPU1_SB_DQS_DN<9>")
	)
	(segment
		(start 31.876746 -237.266734)
		(end 30.771846 -237.266734)
		(width 0.20066)
		(layer "F.Cu")
		(net "M_C_CPU1_SB_DQS_DN<9>")
	)
	(segment
		(start 30.225238 -237.266734)
		(end 30.771846 -237.266734)
		(width 0.20066)
		(layer "F.Cu")
		(net "M_C_CPU1_SB_DQS_DN<9>")
	)
	(segment
		(start 29.132276 -237.953042)
		(end 29.557472 -237.527846)
		(width 0.20066)
		(layer "F.Cu")
		(net "M_C_CPU1_SB_DQS_DN<9>")
	)
	(segment
		(start 25.999694 -237.691676)
		(end 26.065734 -237.691676)
		(width 0.20066)
		(layer "F.Cu")
		(net "M_C_CPU1_SB_DQS_DN<9>")
	)
	(segment
		(start 24.55164 -237.527846)
		(end 25.187656 -237.953042)
		(width 0.20066)
		(layer "F.Cu")
		(net "M_C_CPU1_SB_DQS_DN<9>")
	)
	(segment
		(start 23.228046 -237.266734)
		(end 23.776686 -237.266734)
		(width 0.20066)
		(layer "F.Cu")
		(net "M_C_CPU1_SB_DQS_DN<9>")
	)
	(segment
		(start 91.434666 -240.389156)
		(end 91.434666 -239.85347)
		(width 0.20066)
		(layer "F.Cu")
		(net "M_C_CPU1_SB_DQS_DN<9>")
	)
	(segment
		(start 28.590494 -237.691676)
		(end 28.68422 -237.691676)
		(width 0.20066)
		(layer "F.Cu")
		(net "M_C_CPU1_SB_DQS_DN<9>")
	)
	(segment
		(start 28.945586 -237.953042)
		(end 29.132276 -237.953042)
		(width 0.20066)
		(layer "F.Cu")
		(net "M_C_CPU1_SB_DQS_DN<9>")
	)
	(segment
		(start 26.065734 -237.691676)
		(end 26.21534 -237.691676)
		(width 0.101854)
		(layer "F.Cu")
		(net "M_C_CPU1_SB_DQS_DN<9>")
	)
	(segment
		(start 24.037798 -237.527846)
		(end 24.55164 -237.527846)
		(width 0.20066)
		(layer "F.Cu")
		(net "M_C_CPU1_SB_DQS_DN<9>")
	)
	(segment
		(start 28.68422 -237.691676)
		(end 28.945586 -237.953042)
		(width 0.20066)
		(layer "F.Cu")
		(net "M_C_CPU1_SB_DQS_DN<9>")
	)
	(segment
		(start 23.776686 -237.266734)
		(end 24.037798 -237.527846)
		(width 0.20066)
		(layer "F.Cu")
		(net "M_C_CPU1_SB_DQS_DN<9>")
	)
	(segment
		(start 29.557472 -237.527846)
		(end 29.964126 -237.527846)
		(width 0.20066)
		(layer "F.Cu")
		(net "M_C_CPU1_SB_DQS_DN<9>")
	)
	(segment
		(start 25.187656 -237.953042)
		(end 25.738328 -237.953042)
		(width 0.20066)
		(layer "F.Cu")
		(net "M_C_CPU1_SB_DQS_DN<9>")
	)
	(segment
		(start 28.529026 -237.691676)
		(end 28.590494 -237.691676)
		(width 0.101854)
		(layer "F.Cu")
		(net "M_C_CPU1_SB_DQS_DN<9>")
	)
	(segment
		(start 83.097624 -241.27587)
		(end 83.064096 -241.27587)
		(width 0.088646)
		(layer "In4.Cu")
		(net "M_C_CPU1_SB_DQS_DN<9>")
	)
	(segment
		(start 40.51427 -237.332266)
		(end 39.883842 -237.962694)
		(width 0.18288)
		(layer "In4.Cu")
		(net "M_C_CPU1_SB_DQS_DN<9>")
	)
	(segment
		(start 53.97246 -237.846616)
		(end 53.848 -237.971076)
		(width 0.18288)
		(layer "In4.Cu")
		(net "M_C_CPU1_SB_DQS_DN<9>")
	)
	(segment
		(start 84.201762 -241.33556)
		(end 83.157314 -241.33556)
		(width 0.088646)
		(layer "In4.Cu")
		(net "M_C_CPU1_SB_DQS_DN<9>")
	)
	(segment
		(start 32.135318 -237.525306)
		(end 31.876746 -237.266734)
		(width 0.18288)
		(layer "In4.Cu")
		(net "M_C_CPU1_SB_DQS_DN<9>")
	)
	(segment
		(start 61.82487 -238.186976)
		(end 60.906914 -237.26902)
		(width 0.18288)
		(layer "In4.Cu")
		(net "M_C_CPU1_SB_DQS_DN<9>")
	)
	(segment
		(start 53.848 -237.971076)
		(end 53.29936 -237.971076)
		(width 0.18288)
		(layer "In4.Cu")
		(net "M_C_CPU1_SB_DQS_DN<9>")
	)
	(segment
		(start 65.987676 -238.443008)
		(end 65.439036 -238.443008)
		(width 0.18288)
		(layer "In4.Cu")
		(net "M_C_CPU1_SB_DQS_DN<9>")
	)
	(segment
		(start 51.255676 -237.691676)
		(end 50.871882 -237.691676)
		(width 0.18288)
		(layer "In4.Cu")
		(net "M_C_CPU1_SB_DQS_DN<9>")
	)
	(segment
		(start 53.29936 -237.971076)
		(end 53.1749 -237.846616)
		(width 0.18288)
		(layer "In4.Cu")
		(net "M_C_CPU1_SB_DQS_DN<9>")
	)
	(segment
		(start 52.5018 -237.971076)
		(end 51.535076 -237.971076)
		(width 0.18288)
		(layer "In4.Cu")
		(net "M_C_CPU1_SB_DQS_DN<9>")
	)
	(segment
		(start 63.968376 -238.567468)
		(end 63.419736 -238.567468)
		(width 0.18288)
		(layer "In4.Cu")
		(net "M_C_CPU1_SB_DQS_DN<9>")
	)
	(segment
		(start 88.808306 -240.174272)
		(end 88.802464 -240.177828)
		(width 0.088646)
		(layer "In4.Cu")
		(net "M_C_CPU1_SB_DQS_DN<9>")
	)
	(segment
		(start 53.1749 -237.846616)
		(end 52.62626 -237.846616)
		(width 0.18288)
		(layer "In4.Cu")
		(net "M_C_CPU1_SB_DQS_DN<9>")
	)
	(segment
		(start 91.434412 -239.853216)
		(end 91.402662 -239.96904)
		(width 0.088646)
		(layer "In4.Cu")
		(net "M_C_CPU1_SB_DQS_DN<9>")
	)
	(segment
		(start 83.064096 -241.27587)
		(end 70.503034 -241.27587)
		(width 0.18288)
		(layer "In4.Cu")
		(net "M_C_CPU1_SB_DQS_DN<9>")
	)
	(segment
		(start 51.535076 -237.971076)
		(end 51.255676 -237.691676)
		(width 0.18288)
		(layer "In4.Cu")
		(net "M_C_CPU1_SB_DQS_DN<9>")
	)
	(segment
		(start 52.62626 -237.846616)
		(end 52.5018 -237.971076)
		(width 0.18288)
		(layer "In4.Cu")
		(net "M_C_CPU1_SB_DQS_DN<9>")
	)
	(segment
		(start 65.439036 -238.443008)
		(end 65.314576 -238.567468)
		(width 0.18288)
		(layer "In4.Cu")
		(net "M_C_CPU1_SB_DQS_DN<9>")
	)
	(segment
		(start 35.51428 -237.956598)
		(end 35.031426 -237.956598)
		(width 0.18288)
		(layer "In4.Cu")
		(net "M_C_CPU1_SB_DQS_DN<9>")
	)
	(segment
		(start 43.433746 -237.207806)
		(end 43.309286 -237.332266)
		(width 0.18288)
		(layer "In4.Cu")
		(net "M_C_CPU1_SB_DQS_DN<9>")
	)
	(segment
		(start 47.419514 -238.81588)
		(end 47.145448 -238.541814)
		(width 0.18288)
		(layer "In4.Cu")
		(net "M_C_CPU1_SB_DQS_DN<9>")
	)
	(segment
		(start 64.092836 -238.443008)
		(end 63.968376 -238.567468)
		(width 0.18288)
		(layer "In4.Cu")
		(net "M_C_CPU1_SB_DQS_DN<9>")
	)
	(segment
		(start 50.60696 -237.956598)
		(end 49.917604 -237.956598)
		(width 0.18288)
		(layer "In4.Cu")
		(net "M_C_CPU1_SB_DQS_DN<9>")
	)
	(segment
		(start 54.5211 -237.846616)
		(end 53.97246 -237.846616)
		(width 0.18288)
		(layer "In4.Cu")
		(net "M_C_CPU1_SB_DQS_DN<9>")
	)
	(segment
		(start 64.765936 -238.567468)
		(end 64.641476 -238.443008)
		(width 0.18288)
		(layer "In4.Cu")
		(net "M_C_CPU1_SB_DQS_DN<9>")
	)
	(segment
		(start 86.640416 -240.645188)
		(end 86.640416 -240.667286)
		(width 0.088646)
		(layer "In4.Cu")
		(net "M_C_CPU1_SB_DQS_DN<9>")
	)
	(segment
		(start 69.163184 -239.93602)
		(end 69.163184 -239.759998)
		(width 0.18288)
		(layer "In4.Cu")
		(net "M_C_CPU1_SB_DQS_DN<9>")
	)
	(segment
		(start 88.802464 -240.177828)
		(end 88.798654 -240.17986)
		(width 0.088646)
		(layer "In4.Cu")
		(net "M_C_CPU1_SB_DQS_DN<9>")
	)
	(segment
		(start 36.519358 -237.962694)
		(end 36.24834 -237.691676)
		(width 0.18288)
		(layer "In4.Cu")
		(net "M_C_CPU1_SB_DQS_DN<9>")
	)
	(segment
		(start 49.917604 -237.956598)
		(end 49.058322 -238.81588)
		(width 0.18288)
		(layer "In4.Cu")
		(net "M_C_CPU1_SB_DQS_DN<9>")
	)
	(segment
		(start 64.641476 -238.443008)
		(end 64.092836 -238.443008)
		(width 0.18288)
		(layer "In4.Cu")
		(net "M_C_CPU1_SB_DQS_DN<9>")
	)
	(segment
		(start 91.402662 -239.96904)
		(end 91.3638 -239.991138)
		(width 0.088646)
		(layer "In4.Cu")
		(net "M_C_CPU1_SB_DQS_DN<9>")
	)
	(segment
		(start 90.307668 -240.177574)
		(end 90.297254 -240.171478)
		(width 0.088646)
		(layer "In4.Cu")
		(net "M_C_CPU1_SB_DQS_DN<9>")
	)
	(segment
		(start 46.771814 -238.541814)
		(end 46.506892 -238.806736)
		(width 0.18288)
		(layer "In4.Cu")
		(net "M_C_CPU1_SB_DQS_DN<9>")
	)
	(segment
		(start 63.039244 -238.186976)
		(end 61.82487 -238.186976)
		(width 0.18288)
		(layer "In4.Cu")
		(net "M_C_CPU1_SB_DQS_DN<9>")
	)
	(segment
		(start 69.727064 -240.323878)
		(end 69.551042 -240.323878)
		(width 0.18288)
		(layer "In4.Cu")
		(net "M_C_CPU1_SB_DQS_DN<9>")
	)
	(segment
		(start 70.503034 -241.27587)
		(end 70.115176 -240.888012)
		(width 0.18288)
		(layer "In4.Cu")
		(net "M_C_CPU1_SB_DQS_DN<9>")
	)
	(segment
		(start 63.419736 -238.567468)
		(end 63.039244 -238.186976)
		(width 0.18288)
		(layer "In4.Cu")
		(net "M_C_CPU1_SB_DQS_DN<9>")
	)
	(segment
		(start 57.665874 -237.26902)
		(end 57.541414 -237.14456)
		(width 0.18288)
		(layer "In4.Cu")
		(net "M_C_CPU1_SB_DQS_DN<9>")
	)
	(segment
		(start 66.112136 -238.567468)
		(end 65.987676 -238.443008)
		(width 0.18288)
		(layer "In4.Cu")
		(net "M_C_CPU1_SB_DQS_DN<9>")
	)
	(segment
		(start 88.428068 -240.178082)
		(end 88.427814 -240.177574)
		(width 0.088646)
		(layer "In4.Cu")
		(net "M_C_CPU1_SB_DQS_DN<9>")
	)
	(segment
		(start 87.488014 -240.177574)
		(end 87.473282 -240.168938)
		(width 0.088646)
		(layer "In4.Cu")
		(net "M_C_CPU1_SB_DQS_DN<9>")
	)
	(segment
		(start 88.427814 -240.177574)
		(end 88.413082 -240.168938)
		(width 0.088646)
		(layer "In4.Cu")
		(net "M_C_CPU1_SB_DQS_DN<9>")
	)
	(segment
		(start 69.163184 -239.759998)
		(end 68.775072 -239.371886)
		(width 0.18288)
		(layer "In4.Cu")
		(net "M_C_CPU1_SB_DQS_DN<9>")
	)
	(segment
		(start 85.138768 -240.991644)
		(end 85.13826 -240.991898)
		(width 0.088646)
		(layer "In4.Cu")
		(net "M_C_CPU1_SB_DQS_DN<9>")
	)
	(segment
		(start 55.1942 -237.971076)
		(end 54.64556 -237.971076)
		(width 0.18288)
		(layer "In4.Cu")
		(net "M_C_CPU1_SB_DQS_DN<9>")
	)
	(segment
		(start 34.314638 -237.23981)
		(end 32.71139 -237.23981)
		(width 0.18288)
		(layer "In4.Cu")
		(net "M_C_CPU1_SB_DQS_DN<9>")
	)
	(segment
		(start 43.309286 -237.332266)
		(end 40.51427 -237.332266)
		(width 0.18288)
		(layer "In4.Cu")
		(net "M_C_CPU1_SB_DQS_DN<9>")
	)
	(segment
		(start 43.982386 -237.207806)
		(end 43.433746 -237.207806)
		(width 0.18288)
		(layer "In4.Cu")
		(net "M_C_CPU1_SB_DQS_DN<9>")
	)
	(segment
		(start 49.058322 -238.81588)
		(end 47.419514 -238.81588)
		(width 0.18288)
		(layer "In4.Cu")
		(net "M_C_CPU1_SB_DQS_DN<9>")
	)
	(segment
		(start 70.115176 -240.888012)
		(end 70.115176 -240.71199)
		(width 0.18288)
		(layer "In4.Cu")
		(net "M_C_CPU1_SB_DQS_DN<9>")
	)
	(segment
		(start 35.779202 -237.691676)
		(end 35.51428 -237.956598)
		(width 0.18288)
		(layer "In4.Cu")
		(net "M_C_CPU1_SB_DQS_DN<9>")
	)
	(segment
		(start 83.157314 -241.33556)
		(end 83.097624 -241.27587)
		(width 0.088646)
		(layer "In4.Cu")
		(net "M_C_CPU1_SB_DQS_DN<9>")
	)
	(segment
		(start 36.24834 -237.691676)
		(end 35.779202 -237.691676)
		(width 0.18288)
		(layer "In4.Cu")
		(net "M_C_CPU1_SB_DQS_DN<9>")
	)
	(segment
		(start 55.896256 -237.26902)
		(end 55.1942 -237.971076)
		(width 0.18288)
		(layer "In4.Cu")
		(net "M_C_CPU1_SB_DQS_DN<9>")
	)
	(segment
		(start 68.59905 -239.371886)
		(end 67.794632 -238.567468)
		(width 0.18288)
		(layer "In4.Cu")
		(net "M_C_CPU1_SB_DQS_DN<9>")
	)
	(segment
		(start 32.71139 -237.23981)
		(end 32.425894 -237.525306)
		(width 0.18288)
		(layer "In4.Cu")
		(net "M_C_CPU1_SB_DQS_DN<9>")
	)
	(segment
		(start 54.64556 -237.971076)
		(end 54.5211 -237.846616)
		(width 0.18288)
		(layer "In4.Cu")
		(net "M_C_CPU1_SB_DQS_DN<9>")
	)
	(segment
		(start 90.682318 -240.177828)
		(end 90.682064 -240.177574)
		(width 0.088646)
		(layer "In4.Cu")
		(net "M_C_CPU1_SB_DQS_DN<9>")
	)
	(segment
		(start 84.562696 -240.998502)
		(end 84.561934 -240.99901)
		(width 0.088646)
		(layer "In4.Cu")
		(net "M_C_CPU1_SB_DQS_DN<9>")
	)
	(segment
		(start 90.935556 -240.032032)
		(end 90.682318 -240.177828)
		(width 0.088646)
		(layer "In4.Cu")
		(net "M_C_CPU1_SB_DQS_DN<9>")
	)
	(segment
		(start 60.233814 -237.14456)
		(end 59.685174 -237.14456)
		(width 0.18288)
		(layer "In4.Cu")
		(net "M_C_CPU1_SB_DQS_DN<9>")
	)
	(segment
		(start 89.367614 -240.177574)
		(end 89.367614 -240.177828)
		(width 0.088646)
		(layer "In4.Cu")
		(net "M_C_CPU1_SB_DQS_DN<9>")
	)
	(segment
		(start 32.425894 -237.525306)
		(end 32.135318 -237.525306)
		(width 0.18288)
		(layer "In4.Cu")
		(net "M_C_CPU1_SB_DQS_DN<9>")
	)
	(segment
		(start 60.906914 -237.26902)
		(end 60.358274 -237.26902)
		(width 0.18288)
		(layer "In4.Cu")
		(net "M_C_CPU1_SB_DQS_DN<9>")
	)
	(segment
		(start 44.106846 -237.332266)
		(end 43.982386 -237.207806)
		(width 0.18288)
		(layer "In4.Cu")
		(net "M_C_CPU1_SB_DQS_DN<9>")
	)
	(segment
		(start 65.314576 -238.567468)
		(end 64.765936 -238.567468)
		(width 0.18288)
		(layer "In4.Cu")
		(net "M_C_CPU1_SB_DQS_DN<9>")
	)
	(segment
		(start 39.883842 -237.962694)
		(end 36.519358 -237.962694)
		(width 0.18288)
		(layer "In4.Cu")
		(net "M_C_CPU1_SB_DQS_DN<9>")
	)
	(segment
		(start 46.129956 -238.806736)
		(end 44.655486 -237.332266)
		(width 0.18288)
		(layer "In4.Cu")
		(net "M_C_CPU1_SB_DQS_DN<9>")
	)
	(segment
		(start 84.573872 -240.991898)
		(end 84.562696 -240.998502)
		(width 0.088646)
		(layer "In4.Cu")
		(net "M_C_CPU1_SB_DQS_DN<9>")
	)
	(segment
		(start 84.45627 -241.081052)
		(end 84.201762 -241.33556)
		(width 0.088646)
		(layer "In4.Cu")
		(net "M_C_CPU1_SB_DQS_DN<9>")
	)
	(segment
		(start 70.115176 -240.71199)
		(end 69.727064 -240.323878)
		(width 0.18288)
		(layer "In4.Cu")
		(net "M_C_CPU1_SB_DQS_DN<9>")
	)
	(segment
		(start 56.868314 -237.26902)
		(end 55.896256 -237.26902)
		(width 0.18288)
		(layer "In4.Cu")
		(net "M_C_CPU1_SB_DQS_DN<9>")
	)
	(segment
		(start 91.209114 -240.032032)
		(end 90.935556 -240.032032)
		(width 0.088646)
		(layer "In4.Cu")
		(net "M_C_CPU1_SB_DQS_DN<9>")
	)
	(segment
		(start 67.794632 -238.567468)
		(end 66.112136 -238.567468)
		(width 0.18288)
		(layer "In4.Cu")
		(net "M_C_CPU1_SB_DQS_DN<9>")
	)
	(segment
		(start 47.145448 -238.541814)
		(end 46.771814 -238.541814)
		(width 0.18288)
		(layer "In4.Cu")
		(net "M_C_CPU1_SB_DQS_DN<9>")
	)
	(segment
		(start 58.214514 -237.26902)
		(end 57.665874 -237.26902)
		(width 0.18288)
		(layer "In4.Cu")
		(net "M_C_CPU1_SB_DQS_DN<9>")
	)
	(segment
		(start 46.506892 -238.806736)
		(end 46.129956 -238.806736)
		(width 0.18288)
		(layer "In4.Cu")
		(net "M_C_CPU1_SB_DQS_DN<9>")
	)
	(segment
		(start 57.541414 -237.14456)
		(end 56.992774 -237.14456)
		(width 0.18288)
		(layer "In4.Cu")
		(net "M_C_CPU1_SB_DQS_DN<9>")
	)
	(segment
		(start 60.358274 -237.26902)
		(end 60.233814 -237.14456)
		(width 0.18288)
		(layer "In4.Cu")
		(net "M_C_CPU1_SB_DQS_DN<9>")
	)
	(segment
		(start 35.031426 -237.956598)
		(end 34.314638 -237.23981)
		(width 0.18288)
		(layer "In4.Cu")
		(net "M_C_CPU1_SB_DQS_DN<9>")
	)
	(segment
		(start 56.992774 -237.14456)
		(end 56.868314 -237.26902)
		(width 0.18288)
		(layer "In4.Cu")
		(net "M_C_CPU1_SB_DQS_DN<9>")
	)
	(segment
		(start 58.887614 -237.14456)
		(end 58.338974 -237.14456)
		(width 0.18288)
		(layer "In4.Cu")
		(net "M_C_CPU1_SB_DQS_DN<9>")
	)
	(segment
		(start 59.560714 -237.26902)
		(end 59.012074 -237.26902)
		(width 0.18288)
		(layer "In4.Cu")
		(net "M_C_CPU1_SB_DQS_DN<9>")
	)
	(segment
		(start 84.561934 -240.99901)
		(end 84.561426 -240.999264)
		(width 0.088646)
		(layer "In4.Cu")
		(net "M_C_CPU1_SB_DQS_DN<9>")
	)
	(segment
		(start 68.775072 -239.371886)
		(end 68.59905 -239.371886)
		(width 0.18288)
		(layer "In4.Cu")
		(net "M_C_CPU1_SB_DQS_DN<9>")
	)
	(segment
		(start 58.338974 -237.14456)
		(end 58.214514 -237.26902)
		(width 0.18288)
		(layer "In4.Cu")
		(net "M_C_CPU1_SB_DQS_DN<9>")
	)
	(segment
		(start 50.871882 -237.691676)
		(end 50.60696 -237.956598)
		(width 0.18288)
		(layer "In4.Cu")
		(net "M_C_CPU1_SB_DQS_DN<9>")
	)
	(segment
		(start 59.012074 -237.26902)
		(end 58.887614 -237.14456)
		(width 0.18288)
		(layer "In4.Cu")
		(net "M_C_CPU1_SB_DQS_DN<9>")
	)
	(segment
		(start 59.685174 -237.14456)
		(end 59.560714 -237.26902)
		(width 0.18288)
		(layer "In4.Cu")
		(net "M_C_CPU1_SB_DQS_DN<9>")
	)
	(segment
		(start 44.655486 -237.332266)
		(end 44.106846 -237.332266)
		(width 0.18288)
		(layer "In4.Cu")
		(net "M_C_CPU1_SB_DQS_DN<9>")
	)
	(segment
		(start 69.551042 -240.323878)
		(end 69.163184 -239.93602)
		(width 0.18288)
		(layer "In4.Cu")
		(net "M_C_CPU1_SB_DQS_DN<9>")
	)
	(arc
		(start 84.561426 -240.999264)
		(mid 84.506422 -241.03704)
		(end 84.45627 -241.081052)
		(width 0.088646)
		(layer "In4.Cu")
		(net "M_C_CPU1_SB_DQS_DN<9>")
	)
	(arc
		(start 91.3638 -239.991138)
		(mid 91.289115 -240.021643)
		(end 91.209114 -240.032032)
		(width 0.088646)
		(layer "In4.Cu")
		(net "M_C_CPU1_SB_DQS_DN<9>")
	)
	(arc
		(start 85.13826 -240.991898)
		(mid 84.856066 -240.916342)
		(end 84.573872 -240.991898)
		(width 0.088646)
		(layer "In4.Cu")
		(net "M_C_CPU1_SB_DQS_DN<9>")
	)
	(arc
		(start 89.367614 -240.177828)
		(mid 89.08844 -240.102063)
		(end 88.808306 -240.174272)
		(width 0.088646)
		(layer "In4.Cu")
		(net "M_C_CPU1_SB_DQS_DN<9>")
	)
	(arc
		(start 86.078568 -240.991644)
		(mid 85.795866 -240.915868)
		(end 85.513164 -240.991644)
		(width 0.088646)
		(layer "In4.Cu")
		(net "M_C_CPU1_SB_DQS_DN<9>")
	)
	(arc
		(start 87.86241 -240.177574)
		(mid 87.675212 -240.227717)
		(end 87.488014 -240.177574)
		(width 0.088646)
		(layer "In4.Cu")
		(net "M_C_CPU1_SB_DQS_DN<9>")
	)
	(arc
		(start 87.473282 -240.168938)
		(mid 86.924786 -240.17618)
		(end 86.640416 -240.645188)
		(width 0.088646)
		(layer "In4.Cu")
		(net "M_C_CPU1_SB_DQS_DN<9>")
	)
	(arc
		(start 88.798654 -240.17986)
		(mid 88.613138 -240.227971)
		(end 88.428068 -240.178082)
		(width 0.088646)
		(layer "In4.Cu")
		(net "M_C_CPU1_SB_DQS_DN<9>")
	)
	(arc
		(start 88.413082 -240.168938)
		(mid 88.136641 -240.101772)
		(end 87.86241 -240.177574)
		(width 0.088646)
		(layer "In4.Cu")
		(net "M_C_CPU1_SB_DQS_DN<9>")
	)
	(arc
		(start 85.513164 -240.991644)
		(mid 85.325966 -241.041787)
		(end 85.138768 -240.991644)
		(width 0.088646)
		(layer "In4.Cu")
		(net "M_C_CPU1_SB_DQS_DN<9>")
	)
	(arc
		(start 90.297254 -240.171478)
		(mid 90.018822 -240.101664)
		(end 89.74201 -240.177574)
		(width 0.088646)
		(layer "In4.Cu")
		(net "M_C_CPU1_SB_DQS_DN<9>")
	)
	(arc
		(start 86.640416 -240.667286)
		(mid 86.453117 -240.991727)
		(end 86.078568 -240.991644)
		(width 0.088646)
		(layer "In4.Cu")
		(net "M_C_CPU1_SB_DQS_DN<9>")
	)
	(arc
		(start 90.682064 -240.177574)
		(mid 90.494866 -240.227717)
		(end 90.307668 -240.177574)
		(width 0.088646)
		(layer "In4.Cu")
		(net "M_C_CPU1_SB_DQS_DN<9>")
	)
	(arc
		(start 89.74201 -240.177574)
		(mid 89.554812 -240.227717)
		(end 89.367614 -240.177574)
		(width 0.088646)
		(layer "In4.Cu")
		(net "M_C_CPU1_SB_DQS_DN<9>")
	)
	(segment
		(start 28.534106 -199.605646)
		(end 28.956508 -199.183244)
		(width 0.20066)
		(layer "F.Cu")
		(net "M_C_CPU1_SB_DQS_DN<8>")
	)
	(segment
		(start 34.120328 -199.605646)
		(end 34.38144 -199.866758)
		(width 0.20066)
		(layer "F.Cu")
		(net "M_C_CPU1_SB_DQS_DN<8>")
	)
	(segment
		(start 32.114998 -199.441816)
		(end 32.37611 -199.180704)
		(width 0.20066)
		(layer "F.Cu")
		(net "M_C_CPU1_SB_DQS_DN<8>")
	)
	(segment
		(start 32.780732 -199.180704)
		(end 33.416748 -199.605646)
		(width 0.20066)
		(layer "F.Cu")
		(net "M_C_CPU1_SB_DQS_DN<8>")
	)
	(segment
		(start 27.799792 -199.866758)
		(end 28.060904 -199.605646)
		(width 0.20066)
		(layer "F.Cu")
		(net "M_C_CPU1_SB_DQS_DN<8>")
	)
	(segment
		(start 27.328114 -199.866758)
		(end 27.799792 -199.866758)
		(width 0.20066)
		(layer "F.Cu")
		(net "M_C_CPU1_SB_DQS_DN<8>")
	)
	(segment
		(start 29.655516 -199.441816)
		(end 29.895292 -199.441816)
		(width 0.101854)
		(layer "F.Cu")
		(net "M_C_CPU1_SB_DQS_DN<8>")
	)
	(segment
		(start 96.603312 -228.1809)
		(end 96.603312 -227.645214)
		(width 0.20066)
		(layer "F.Cu")
		(net "M_C_CPU1_SB_DQS_DN<8>")
	)
	(segment
		(start 31.972758 -199.441816)
		(end 32.114998 -199.441816)
		(width 0.20066)
		(layer "F.Cu")
		(net "M_C_CPU1_SB_DQS_DN<8>")
	)
	(segment
		(start 28.956508 -199.183244)
		(end 29.196284 -199.183244)
		(width 0.20066)
		(layer "F.Cu")
		(net "M_C_CPU1_SB_DQS_DN<8>")
	)
	(segment
		(start 35.976814 -199.866758)
		(end 34.871914 -199.866758)
		(width 0.20066)
		(layer "F.Cu")
		(net "M_C_CPU1_SB_DQS_DN<8>")
	)
	(segment
		(start 32.37611 -199.180704)
		(end 32.780732 -199.180704)
		(width 0.20066)
		(layer "F.Cu")
		(net "M_C_CPU1_SB_DQS_DN<8>")
	)
	(segment
		(start 29.647642 -199.44969)
		(end 29.655516 -199.441816)
		(width 0.101854)
		(layer "F.Cu")
		(net "M_C_CPU1_SB_DQS_DN<8>")
	)
	(segment
		(start 96.603312 -227.645214)
		(end 96.603566 -227.64496)
		(width 0.20066)
		(layer "F.Cu")
		(net "M_C_CPU1_SB_DQS_DN<8>")
	)
	(segment
		(start 33.416748 -199.605646)
		(end 34.120328 -199.605646)
		(width 0.20066)
		(layer "F.Cu")
		(net "M_C_CPU1_SB_DQS_DN<8>")
	)
	(segment
		(start 29.196284 -199.183244)
		(end 29.46273 -199.44969)
		(width 0.20066)
		(layer "F.Cu")
		(net "M_C_CPU1_SB_DQS_DN<8>")
	)
	(segment
		(start 28.060904 -199.605646)
		(end 28.534106 -199.605646)
		(width 0.20066)
		(layer "F.Cu")
		(net "M_C_CPU1_SB_DQS_DN<8>")
	)
	(segment
		(start 29.46273 -199.44969)
		(end 29.647642 -199.44969)
		(width 0.20066)
		(layer "F.Cu")
		(net "M_C_CPU1_SB_DQS_DN<8>")
	)
	(segment
		(start 34.38144 -199.866758)
		(end 34.871914 -199.866758)
		(width 0.20066)
		(layer "F.Cu")
		(net "M_C_CPU1_SB_DQS_DN<8>")
	)
	(segment
		(start 29.895292 -199.441816)
		(end 31.972758 -199.441816)
		(width 0.1016)
		(layer "F.Cu")
		(net "M_C_CPU1_SB_DQS_DN<8>")
	)
	(segment
		(start 96.603566 -227.64496)
		(end 96.571816 -227.529136)
		(width 0.088646)
		(layer "In6.Cu")
		(net "M_C_CPU1_SB_DQS_DN<8>")
	)
	(segment
		(start 69.03212 -204.194664)
		(end 68.856098 -204.194664)
		(width 0.18288)
		(layer "In6.Cu")
		(net "M_C_CPU1_SB_DQS_DN<8>")
	)
	(segment
		(start 88.341454 -225.69805)
		(end 88.332564 -225.69297)
		(width 0.088646)
		(layer "In6.Cu")
		(net "M_C_CPU1_SB_DQS_DN<8>")
	)
	(segment
		(start 83.184746 -222.545148)
		(end 82.5627 -222.545148)
		(width 0.088646)
		(layer "In6.Cu")
		(net "M_C_CPU1_SB_DQS_DN<8>")
	)
	(segment
		(start 85.057996 -224.887536)
		(end 85.043264 -224.8789)
		(width 0.088646)
		(layer "In6.Cu")
		(net "M_C_CPU1_SB_DQS_DN<8>")
	)
	(segment
		(start 66.54292 -201.705464)
		(end 65.573148 -201.705464)
		(width 0.18288)
		(layer "In6.Cu")
		(net "M_C_CPU1_SB_DQS_DN<8>")
	)
	(segment
		(start 45.748194 -197.475094)
		(end 45.135546 -196.862446)
		(width 0.18288)
		(layer "In6.Cu")
		(net "M_C_CPU1_SB_DQS_DN<8>")
	)
	(segment
		(start 36.472114 -199.087486)
		(end 36.472114 -199.371458)
		(width 0.18288)
		(layer "In6.Cu")
		(net "M_C_CPU1_SB_DQS_DN<8>")
	)
	(segment
		(start 92.570554 -226.511866)
		(end 92.561664 -226.506786)
		(width 0.088646)
		(layer "In6.Cu")
		(net "M_C_CPU1_SB_DQS_DN<8>")
	)
	(segment
		(start 68.467986 -203.806552)
		(end 68.467986 -203.63053)
		(width 0.18288)
		(layer "In6.Cu")
		(net "M_C_CPU1_SB_DQS_DN<8>")
	)
	(segment
		(start 57.878726 -197.757542)
		(end 57.330086 -197.757542)
		(width 0.18288)
		(layer "In6.Cu")
		(net "M_C_CPU1_SB_DQS_DN<8>")
	)
	(segment
		(start 82.479642 -222.604838)
		(end 81.31429 -222.604838)
		(width 0.18288)
		(layer "In6.Cu")
		(net "M_C_CPU1_SB_DQS_DN<8>")
	)
	(segment
		(start 37.31895 -198.072502)
		(end 36.793424 -198.598028)
		(width 0.18288)
		(layer "In6.Cu")
		(net "M_C_CPU1_SB_DQS_DN<8>")
	)
	(segment
		(start 43.181778 -197.645274)
		(end 42.51833 -198.308722)
		(width 0.18288)
		(layer "In6.Cu")
		(net "M_C_CPU1_SB_DQS_DN<8>")
	)
	(segment
		(start 50.865532 -196.889116)
		(end 50.614834 -196.638418)
		(width 0.18288)
		(layer "In6.Cu")
		(net "M_C_CPU1_SB_DQS_DN<8>")
	)
	(segment
		(start 60.477908 -198.65467)
		(end 60.09005 -198.266812)
		(width 0.18288)
		(layer "In6.Cu")
		(net "M_C_CPU1_SB_DQS_DN<8>")
	)
	(segment
		(start 53.903626 -196.625718)
		(end 53.779166 -196.750178)
		(width 0.18288)
		(layer "In6.Cu")
		(net "M_C_CPU1_SB_DQS_DN<8>")
	)
	(segment
		(start 50.435764 -196.638418)
		(end 48.421798 -197.472554)
		(width 0.18288)
		(layer "In6.Cu")
		(net "M_C_CPU1_SB_DQS_DN<8>")
	)
	(segment
		(start 83.440778 -222.80118)
		(end 83.184746 -222.545148)
		(width 0.088646)
		(layer "In6.Cu")
		(net "M_C_CPU1_SB_DQS_DN<8>")
	)
	(segment
		(start 93.986096 -227.329238)
		(end 93.971364 -227.320602)
		(width 0.088646)
		(layer "In6.Cu")
		(net "M_C_CPU1_SB_DQS_DN<8>")
	)
	(segment
		(start 46.761654 -197.740778)
		(end 46.49597 -197.475094)
		(width 0.18288)
		(layer "In6.Cu")
		(net "M_C_CPU1_SB_DQS_DN<8>")
	)
	(segment
		(start 51.519836 -196.625718)
		(end 51.256438 -196.889116)
		(width 0.18288)
		(layer "In6.Cu")
		(net "M_C_CPU1_SB_DQS_DN<8>")
	)
	(segment
		(start 96.571816 -227.529136)
		(end 96.532954 -227.507038)
		(width 0.088646)
		(layer "In6.Cu")
		(net "M_C_CPU1_SB_DQS_DN<8>")
	)
	(segment
		(start 42.51833 -198.308722)
		(end 41.79697 -198.308722)
		(width 0.18288)
		(layer "In6.Cu")
		(net "M_C_CPU1_SB_DQS_DN<8>")
	)
	(segment
		(start 63.99911 -200.131426)
		(end 62.705488 -200.131426)
		(width 0.18288)
		(layer "In6.Cu")
		(net "M_C_CPU1_SB_DQS_DN<8>")
	)
	(segment
		(start 60.86602 -199.218804)
		(end 60.477908 -198.830692)
		(width 0.18288)
		(layer "In6.Cu")
		(net "M_C_CPU1_SB_DQS_DN<8>")
	)
	(segment
		(start 48.421798 -197.472554)
		(end 47.426372 -197.472554)
		(width 0.18288)
		(layer "In6.Cu")
		(net "M_C_CPU1_SB_DQS_DN<8>")
	)
	(segment
		(start 68.467986 -203.63053)
		(end 68.080128 -203.242672)
		(width 0.18288)
		(layer "In6.Cu")
		(net "M_C_CPU1_SB_DQS_DN<8>")
	)
	(segment
		(start 96.10471 -227.466144)
		(end 95.850964 -227.320602)
		(width 0.088646)
		(layer "In6.Cu")
		(net "M_C_CPU1_SB_DQS_DN<8>")
	)
	(segment
		(start 41.79697 -198.308722)
		(end 41.498266 -198.607426)
		(width 0.18288)
		(layer "In6.Cu")
		(net "M_C_CPU1_SB_DQS_DN<8>")
	)
	(segment
		(start 90.692224 -226.512882)
		(end 90.68181 -226.506786)
		(width 0.088646)
		(layer "In6.Cu")
		(net "M_C_CPU1_SB_DQS_DN<8>")
	)
	(segment
		(start 83.440778 -223.617282)
		(end 83.440778 -222.80118)
		(width 0.088646)
		(layer "In6.Cu")
		(net "M_C_CPU1_SB_DQS_DN<8>")
	)
	(segment
		(start 47.426372 -197.472554)
		(end 47.158148 -197.740778)
		(width 0.18288)
		(layer "In6.Cu")
		(net "M_C_CPU1_SB_DQS_DN<8>")
	)
	(segment
		(start 67.904106 -203.242672)
		(end 67.515994 -202.85456)
		(width 0.18288)
		(layer "In6.Cu")
		(net "M_C_CPU1_SB_DQS_DN<8>")
	)
	(segment
		(start 93.046296 -227.329238)
		(end 93.031564 -227.320602)
		(width 0.088646)
		(layer "In6.Cu")
		(net "M_C_CPU1_SB_DQS_DN<8>")
	)
	(segment
		(start 61.042042 -199.218804)
		(end 60.86602 -199.218804)
		(width 0.18288)
		(layer "In6.Cu")
		(net "M_C_CPU1_SB_DQS_DN<8>")
	)
	(segment
		(start 41.498266 -198.607426)
		(end 41.111932 -198.607426)
		(width 0.18288)
		(layer "In6.Cu")
		(net "M_C_CPU1_SB_DQS_DN<8>")
	)
	(segment
		(start 59.043824 -197.633082)
		(end 58.003186 -197.633082)
		(width 0.18288)
		(layer "In6.Cu")
		(net "M_C_CPU1_SB_DQS_DN<8>")
	)
	(segment
		(start 62.705488 -200.131426)
		(end 61.423804 -199.600566)
		(width 0.18288)
		(layer "In6.Cu")
		(net "M_C_CPU1_SB_DQS_DN<8>")
	)
	(segment
		(start 87.871554 -224.88398)
		(end 87.862664 -224.8789)
		(width 0.088646)
		(layer "In6.Cu")
		(net "M_C_CPU1_SB_DQS_DN<8>")
	)
	(segment
		(start 81.31429 -222.604838)
		(end 80.747108 -222.037656)
		(width 0.18288)
		(layer "In6.Cu")
		(net "M_C_CPU1_SB_DQS_DN<8>")
	)
	(segment
		(start 88.520016 -226.032822)
		(end 88.520016 -226.017328)
		(width 0.088646)
		(layer "In6.Cu")
		(net "M_C_CPU1_SB_DQS_DN<8>")
	)
	(segment
		(start 58.003186 -197.633082)
		(end 57.878726 -197.757542)
		(width 0.18288)
		(layer "In6.Cu")
		(net "M_C_CPU1_SB_DQS_DN<8>")
	)
	(segment
		(start 40.834818 -198.330312)
		(end 40.190928 -198.330312)
		(width 0.18288)
		(layer "In6.Cu")
		(net "M_C_CPU1_SB_DQS_DN<8>")
	)
	(segment
		(start 94.925896 -227.329238)
		(end 94.911164 -227.320602)
		(width 0.088646)
		(layer "In6.Cu")
		(net "M_C_CPU1_SB_DQS_DN<8>")
	)
	(segment
		(start 72.106536 -211.125308)
		(end 69.419978 -204.582522)
		(width 0.18288)
		(layer "In6.Cu")
		(net "M_C_CPU1_SB_DQS_DN<8>")
	)
	(segment
		(start 60.09005 -198.266812)
		(end 59.677554 -198.266812)
		(width 0.18288)
		(layer "In6.Cu")
		(net "M_C_CPU1_SB_DQS_DN<8>")
	)
	(segment
		(start 47.158148 -197.740778)
		(end 46.761654 -197.740778)
		(width 0.18288)
		(layer "In6.Cu")
		(net "M_C_CPU1_SB_DQS_DN<8>")
	)
	(segment
		(start 36.793424 -198.766176)
		(end 36.472114 -199.087486)
		(width 0.18288)
		(layer "In6.Cu")
		(net "M_C_CPU1_SB_DQS_DN<8>")
	)
	(segment
		(start 88.050116 -225.2218)
		(end 88.050116 -225.203258)
		(width 0.088646)
		(layer "In6.Cu")
		(net "M_C_CPU1_SB_DQS_DN<8>")
	)
	(segment
		(start 36.472114 -199.371458)
		(end 35.976814 -199.866758)
		(width 0.18288)
		(layer "In6.Cu")
		(net "M_C_CPU1_SB_DQS_DN<8>")
	)
	(segment
		(start 69.419978 -204.582522)
		(end 69.03212 -204.194664)
		(width 0.18288)
		(layer "In6.Cu")
		(net "M_C_CPU1_SB_DQS_DN<8>")
	)
	(segment
		(start 89.367614 -226.506786)
		(end 89.352882 -226.515422)
		(width 0.088646)
		(layer "In6.Cu")
		(net "M_C_CPU1_SB_DQS_DN<8>")
	)
	(segment
		(start 53.779166 -196.750178)
		(end 53.230526 -196.750178)
		(width 0.18288)
		(layer "In6.Cu")
		(net "M_C_CPU1_SB_DQS_DN<8>")
	)
	(segment
		(start 53.106066 -196.625718)
		(end 51.519836 -196.625718)
		(width 0.18288)
		(layer "In6.Cu")
		(net "M_C_CPU1_SB_DQS_DN<8>")
	)
	(segment
		(start 80.747108 -222.037656)
		(end 80.747108 -219.76588)
		(width 0.18288)
		(layer "In6.Cu")
		(net "M_C_CPU1_SB_DQS_DN<8>")
	)
	(segment
		(start 57.205626 -197.633082)
		(end 55.615078 -197.633082)
		(width 0.18288)
		(layer "In6.Cu")
		(net "M_C_CPU1_SB_DQS_DN<8>")
	)
	(segment
		(start 54.607714 -196.625718)
		(end 53.903626 -196.625718)
		(width 0.18288)
		(layer "In6.Cu")
		(net "M_C_CPU1_SB_DQS_DN<8>")
	)
	(segment
		(start 96.378268 -227.466144)
		(end 96.10471 -227.466144)
		(width 0.088646)
		(layer "In6.Cu")
		(net "M_C_CPU1_SB_DQS_DN<8>")
	)
	(segment
		(start 92.749116 -226.84105)
		(end 92.749116 -226.831144)
		(width 0.088646)
		(layer "In6.Cu")
		(net "M_C_CPU1_SB_DQS_DN<8>")
	)
	(segment
		(start 53.230526 -196.750178)
		(end 53.106066 -196.625718)
		(width 0.18288)
		(layer "In6.Cu")
		(net "M_C_CPU1_SB_DQS_DN<8>")
	)
	(segment
		(start 44.497752 -196.862446)
		(end 44.092114 -197.268084)
		(width 0.18288)
		(layer "In6.Cu")
		(net "M_C_CPU1_SB_DQS_DN<8>")
	)
	(segment
		(start 82.5627 -222.545148)
		(end 82.50301 -222.604838)
		(width 0.088646)
		(layer "In6.Cu")
		(net "M_C_CPU1_SB_DQS_DN<8>")
	)
	(segment
		(start 40.190928 -198.330312)
		(end 39.933118 -198.072502)
		(width 0.18288)
		(layer "In6.Cu")
		(net "M_C_CPU1_SB_DQS_DN<8>")
	)
	(segment
		(start 57.330086 -197.757542)
		(end 57.205626 -197.633082)
		(width 0.18288)
		(layer "In6.Cu")
		(net "M_C_CPU1_SB_DQS_DN<8>")
	)
	(segment
		(start 44.092114 -197.268084)
		(end 43.181778 -197.645274)
		(width 0.18288)
		(layer "In6.Cu")
		(net "M_C_CPU1_SB_DQS_DN<8>")
	)
	(segment
		(start 46.49597 -197.475094)
		(end 45.748194 -197.475094)
		(width 0.18288)
		(layer "In6.Cu")
		(net "M_C_CPU1_SB_DQS_DN<8>")
	)
	(segment
		(start 60.477908 -198.830692)
		(end 60.477908 -198.65467)
		(width 0.18288)
		(layer "In6.Cu")
		(net "M_C_CPU1_SB_DQS_DN<8>")
	)
	(segment
		(start 59.677554 -198.266812)
		(end 59.043824 -197.633082)
		(width 0.18288)
		(layer "In6.Cu")
		(net "M_C_CPU1_SB_DQS_DN<8>")
	)
	(segment
		(start 80.747108 -219.76588)
		(end 72.106536 -211.125308)
		(width 0.18288)
		(layer "In6.Cu")
		(net "M_C_CPU1_SB_DQS_DN<8>")
	)
	(segment
		(start 61.423804 -199.600566)
		(end 61.042042 -199.218804)
		(width 0.18288)
		(layer "In6.Cu")
		(net "M_C_CPU1_SB_DQS_DN<8>")
	)
	(segment
		(start 51.256438 -196.889116)
		(end 50.865532 -196.889116)
		(width 0.18288)
		(layer "In6.Cu")
		(net "M_C_CPU1_SB_DQS_DN<8>")
	)
	(segment
		(start 65.573148 -201.705464)
		(end 63.99911 -200.131426)
		(width 0.18288)
		(layer "In6.Cu")
		(net "M_C_CPU1_SB_DQS_DN<8>")
	)
	(segment
		(start 68.856098 -204.194664)
		(end 68.467986 -203.806552)
		(width 0.18288)
		(layer "In6.Cu")
		(net "M_C_CPU1_SB_DQS_DN<8>")
	)
	(segment
		(start 55.615078 -197.633082)
		(end 54.607714 -196.625718)
		(width 0.18288)
		(layer "In6.Cu")
		(net "M_C_CPU1_SB_DQS_DN<8>")
	)
	(segment
		(start 67.515994 -202.85456)
		(end 67.515994 -202.678538)
		(width 0.18288)
		(layer "In6.Cu")
		(net "M_C_CPU1_SB_DQS_DN<8>")
	)
	(segment
		(start 68.080128 -203.242672)
		(end 67.904106 -203.242672)
		(width 0.18288)
		(layer "In6.Cu")
		(net "M_C_CPU1_SB_DQS_DN<8>")
	)
	(segment
		(start 84.65185 -224.828354)
		(end 83.440778 -223.617282)
		(width 0.088646)
		(layer "In6.Cu")
		(net "M_C_CPU1_SB_DQS_DN<8>")
	)
	(segment
		(start 90.307414 -226.506786)
		(end 90.292682 -226.515422)
		(width 0.088646)
		(layer "In6.Cu")
		(net "M_C_CPU1_SB_DQS_DN<8>")
	)
	(segment
		(start 82.50301 -222.604838)
		(end 82.479642 -222.604838)
		(width 0.088646)
		(layer "In6.Cu")
		(net "M_C_CPU1_SB_DQS_DN<8>")
	)
	(segment
		(start 50.614834 -196.638418)
		(end 50.435764 -196.638418)
		(width 0.18288)
		(layer "In6.Cu")
		(net "M_C_CPU1_SB_DQS_DN<8>")
	)
	(segment
		(start 39.933118 -198.072502)
		(end 37.31895 -198.072502)
		(width 0.18288)
		(layer "In6.Cu")
		(net "M_C_CPU1_SB_DQS_DN<8>")
	)
	(segment
		(start 36.793424 -198.598028)
		(end 36.793424 -198.766176)
		(width 0.18288)
		(layer "In6.Cu")
		(net "M_C_CPU1_SB_DQS_DN<8>")
	)
	(segment
		(start 45.135546 -196.862446)
		(end 44.497752 -196.862446)
		(width 0.18288)
		(layer "In6.Cu")
		(net "M_C_CPU1_SB_DQS_DN<8>")
	)
	(segment
		(start 84.85632 -224.828354)
		(end 84.65185 -224.828354)
		(width 0.088646)
		(layer "In6.Cu")
		(net "M_C_CPU1_SB_DQS_DN<8>")
	)
	(segment
		(start 41.111932 -198.607426)
		(end 40.834818 -198.330312)
		(width 0.18288)
		(layer "In6.Cu")
		(net "M_C_CPU1_SB_DQS_DN<8>")
	)
	(segment
		(start 67.515994 -202.678538)
		(end 66.54292 -201.705464)
		(width 0.18288)
		(layer "In6.Cu")
		(net "M_C_CPU1_SB_DQS_DN<8>")
	)
	(arc
		(start 88.80221 -226.506786)
		(mid 88.599387 -226.306555)
		(end 88.520016 -226.032822)
		(width 0.088646)
		(layer "In6.Cu")
		(net "M_C_CPU1_SB_DQS_DN<8>")
	)
	(arc
		(start 85.043264 -224.8789)
		(mid 84.964473 -224.844599)
		(end 84.879942 -224.829116)
		(width 0.088646)
		(layer "In6.Cu")
		(net "M_C_CPU1_SB_DQS_DN<8>")
	)
	(arc
		(start 87.862664 -224.8789)
		(mid 87.675466 -224.828757)
		(end 87.488268 -224.8789)
		(width 0.088646)
		(layer "In6.Cu")
		(net "M_C_CPU1_SB_DQS_DN<8>")
	)
	(arc
		(start 90.292682 -226.515422)
		(mid 90.016207 -226.582742)
		(end 89.74201 -226.506786)
		(width 0.088646)
		(layer "In6.Cu")
		(net "M_C_CPU1_SB_DQS_DN<8>")
	)
	(arc
		(start 94.911164 -227.320602)
		(mid 94.723966 -227.270459)
		(end 94.536768 -227.320602)
		(width 0.088646)
		(layer "In6.Cu")
		(net "M_C_CPU1_SB_DQS_DN<8>")
	)
	(arc
		(start 86.922864 -224.8789)
		(mid 86.735666 -224.828757)
		(end 86.548468 -224.8789)
		(width 0.088646)
		(layer "In6.Cu")
		(net "M_C_CPU1_SB_DQS_DN<8>")
	)
	(arc
		(start 88.050116 -225.203258)
		(mid 88.002437 -225.020358)
		(end 87.871554 -224.88398)
		(width 0.088646)
		(layer "In6.Cu")
		(net "M_C_CPU1_SB_DQS_DN<8>")
	)
	(arc
		(start 92.749116 -226.831144)
		(mid 92.701437 -226.648244)
		(end 92.570554 -226.511866)
		(width 0.088646)
		(layer "In6.Cu")
		(net "M_C_CPU1_SB_DQS_DN<8>")
	)
	(arc
		(start 92.187268 -226.506786)
		(mid 91.904566 -226.582562)
		(end 91.621864 -226.506786)
		(width 0.088646)
		(layer "In6.Cu")
		(net "M_C_CPU1_SB_DQS_DN<8>")
	)
	(arc
		(start 91.247468 -226.506786)
		(mid 90.970655 -226.582656)
		(end 90.692224 -226.512882)
		(width 0.088646)
		(layer "In6.Cu")
		(net "M_C_CPU1_SB_DQS_DN<8>")
	)
	(arc
		(start 93.596968 -227.320602)
		(mid 93.322769 -227.396437)
		(end 93.046296 -227.329238)
		(width 0.088646)
		(layer "In6.Cu")
		(net "M_C_CPU1_SB_DQS_DN<8>")
	)
	(arc
		(start 88.332564 -225.69297)
		(mid 88.130278 -225.493989)
		(end 88.050116 -225.2218)
		(width 0.088646)
		(layer "In6.Cu")
		(net "M_C_CPU1_SB_DQS_DN<8>")
	)
	(arc
		(start 88.520016 -226.017328)
		(mid 88.472337 -225.834428)
		(end 88.341454 -225.69805)
		(width 0.088646)
		(layer "In6.Cu")
		(net "M_C_CPU1_SB_DQS_DN<8>")
	)
	(arc
		(start 95.476568 -227.320602)
		(mid 95.202369 -227.396437)
		(end 94.925896 -227.329238)
		(width 0.088646)
		(layer "In6.Cu")
		(net "M_C_CPU1_SB_DQS_DN<8>")
	)
	(arc
		(start 85.608668 -224.8789)
		(mid 85.334469 -224.954735)
		(end 85.057996 -224.887536)
		(width 0.088646)
		(layer "In6.Cu")
		(net "M_C_CPU1_SB_DQS_DN<8>")
	)
	(arc
		(start 91.621864 -226.506786)
		(mid 91.434666 -226.456643)
		(end 91.247468 -226.506786)
		(width 0.088646)
		(layer "In6.Cu")
		(net "M_C_CPU1_SB_DQS_DN<8>")
	)
	(arc
		(start 87.488268 -224.8789)
		(mid 87.205566 -224.954676)
		(end 86.922864 -224.8789)
		(width 0.088646)
		(layer "In6.Cu")
		(net "M_C_CPU1_SB_DQS_DN<8>")
	)
	(arc
		(start 95.850964 -227.320602)
		(mid 95.663766 -227.270459)
		(end 95.476568 -227.320602)
		(width 0.088646)
		(layer "In6.Cu")
		(net "M_C_CPU1_SB_DQS_DN<8>")
	)
	(arc
		(start 89.74201 -226.506786)
		(mid 89.554812 -226.456643)
		(end 89.367614 -226.506786)
		(width 0.088646)
		(layer "In6.Cu")
		(net "M_C_CPU1_SB_DQS_DN<8>")
	)
	(arc
		(start 86.548468 -224.8789)
		(mid 86.265766 -224.954676)
		(end 85.983064 -224.8789)
		(width 0.088646)
		(layer "In6.Cu")
		(net "M_C_CPU1_SB_DQS_DN<8>")
	)
	(arc
		(start 89.352882 -226.515422)
		(mid 89.076407 -226.582742)
		(end 88.80221 -226.506786)
		(width 0.088646)
		(layer "In6.Cu")
		(net "M_C_CPU1_SB_DQS_DN<8>")
	)
	(arc
		(start 92.561664 -226.506786)
		(mid 92.374466 -226.456643)
		(end 92.187268 -226.506786)
		(width 0.088646)
		(layer "In6.Cu")
		(net "M_C_CPU1_SB_DQS_DN<8>")
	)
	(arc
		(start 90.68181 -226.506786)
		(mid 90.494612 -226.456643)
		(end 90.307414 -226.506786)
		(width 0.088646)
		(layer "In6.Cu")
		(net "M_C_CPU1_SB_DQS_DN<8>")
	)
	(arc
		(start 93.031564 -227.320602)
		(mid 92.827229 -227.117997)
		(end 92.749116 -226.84105)
		(width 0.088646)
		(layer "In6.Cu")
		(net "M_C_CPU1_SB_DQS_DN<8>")
	)
	(arc
		(start 96.532954 -227.507038)
		(mid 96.458269 -227.476533)
		(end 96.378268 -227.466144)
		(width 0.088646)
		(layer "In6.Cu")
		(net "M_C_CPU1_SB_DQS_DN<8>")
	)
	(arc
		(start 85.983064 -224.8789)
		(mid 85.795866 -224.828757)
		(end 85.608668 -224.8789)
		(width 0.088646)
		(layer "In6.Cu")
		(net "M_C_CPU1_SB_DQS_DN<8>")
	)
	(arc
		(start 93.971364 -227.320602)
		(mid 93.784166 -227.270459)
		(end 93.596968 -227.320602)
		(width 0.088646)
		(layer "In6.Cu")
		(net "M_C_CPU1_SB_DQS_DN<8>")
	)
	(arc
		(start 84.879942 -224.829116)
		(mid 84.868137 -224.828549)
		(end 84.85632 -224.828354)
		(width 0.088646)
		(layer "In6.Cu")
		(net "M_C_CPU1_SB_DQS_DN<8>")
	)
	(arc
		(start 94.536768 -227.320602)
		(mid 94.262569 -227.396437)
		(end 93.986096 -227.329238)
		(width 0.088646)
		(layer "In6.Cu")
		(net "M_C_CPU1_SB_DQS_DN<8>")
	)
	(segment
		(start 28.060904 -208.95564)
		(end 28.534106 -208.95564)
		(width 0.20066)
		(layer "F.Cu")
		(net "M_C_CPU1_SB_DQS_DN<7>")
	)
	(segment
		(start 28.956508 -208.533238)
		(end 29.196284 -208.533238)
		(width 0.20066)
		(layer "F.Cu")
		(net "M_C_CPU1_SB_DQS_DN<7>")
	)
	(segment
		(start 29.655516 -208.79181)
		(end 29.895292 -208.79181)
		(width 0.101854)
		(layer "F.Cu")
		(net "M_C_CPU1_SB_DQS_DN<7>")
	)
	(segment
		(start 32.780732 -208.530698)
		(end 33.416748 -208.95564)
		(width 0.20066)
		(layer "F.Cu")
		(net "M_C_CPU1_SB_DQS_DN<7>")
	)
	(segment
		(start 32.114998 -208.79181)
		(end 32.37611 -208.530698)
		(width 0.20066)
		(layer "F.Cu")
		(net "M_C_CPU1_SB_DQS_DN<7>")
	)
	(segment
		(start 29.46273 -208.799684)
		(end 29.647642 -208.799684)
		(width 0.20066)
		(layer "F.Cu")
		(net "M_C_CPU1_SB_DQS_DN<7>")
	)
	(segment
		(start 27.328114 -209.216752)
		(end 27.799792 -209.216752)
		(width 0.20066)
		(layer "F.Cu")
		(net "M_C_CPU1_SB_DQS_DN<7>")
	)
	(segment
		(start 34.120328 -208.95564)
		(end 34.38144 -209.216752)
		(width 0.20066)
		(layer "F.Cu")
		(net "M_C_CPU1_SB_DQS_DN<7>")
	)
	(segment
		(start 33.416748 -208.95564)
		(end 34.120328 -208.95564)
		(width 0.20066)
		(layer "F.Cu")
		(net "M_C_CPU1_SB_DQS_DN<7>")
	)
	(segment
		(start 34.38144 -209.216752)
		(end 34.871914 -209.216752)
		(width 0.20066)
		(layer "F.Cu")
		(net "M_C_CPU1_SB_DQS_DN<7>")
	)
	(segment
		(start 32.37611 -208.530698)
		(end 32.780732 -208.530698)
		(width 0.20066)
		(layer "F.Cu")
		(net "M_C_CPU1_SB_DQS_DN<7>")
	)
	(segment
		(start 29.196284 -208.533238)
		(end 29.46273 -208.799684)
		(width 0.20066)
		(layer "F.Cu")
		(net "M_C_CPU1_SB_DQS_DN<7>")
	)
	(segment
		(start 31.972758 -208.79181)
		(end 32.114998 -208.79181)
		(width 0.20066)
		(layer "F.Cu")
		(net "M_C_CPU1_SB_DQS_DN<7>")
	)
	(segment
		(start 28.534106 -208.95564)
		(end 28.956508 -208.533238)
		(width 0.20066)
		(layer "F.Cu")
		(net "M_C_CPU1_SB_DQS_DN<7>")
	)
	(segment
		(start 35.976814 -209.216752)
		(end 34.871914 -209.216752)
		(width 0.20066)
		(layer "F.Cu")
		(net "M_C_CPU1_SB_DQS_DN<7>")
	)
	(segment
		(start 93.314266 -230.622602)
		(end 93.314266 -230.086916)
		(width 0.20066)
		(layer "F.Cu")
		(net "M_C_CPU1_SB_DQS_DN<7>")
	)
	(segment
		(start 27.799792 -209.216752)
		(end 28.060904 -208.95564)
		(width 0.20066)
		(layer "F.Cu")
		(net "M_C_CPU1_SB_DQS_DN<7>")
	)
	(segment
		(start 93.314266 -230.086916)
		(end 93.314012 -230.086662)
		(width 0.20066)
		(layer "F.Cu")
		(net "M_C_CPU1_SB_DQS_DN<7>")
	)
	(segment
		(start 29.895292 -208.79181)
		(end 31.972758 -208.79181)
		(width 0.1016)
		(layer "F.Cu")
		(net "M_C_CPU1_SB_DQS_DN<7>")
	)
	(segment
		(start 29.647642 -208.799684)
		(end 29.655516 -208.79181)
		(width 0.101854)
		(layer "F.Cu")
		(net "M_C_CPU1_SB_DQS_DN<7>")
	)
	(segment
		(start 64.99733 -211.149184)
		(end 64.87287 -211.024724)
		(width 0.18288)
		(layer "In4.Cu")
		(net "M_C_CPU1_SB_DQS_DN<7>")
	)
	(segment
		(start 64.87287 -211.024724)
		(end 63.32474 -211.024724)
		(width 0.18288)
		(layer "In4.Cu")
		(net "M_C_CPU1_SB_DQS_DN<7>")
	)
	(segment
		(start 71.458074 -222.205804)
		(end 67.25285 -212.058504)
		(width 0.18288)
		(layer "In4.Cu")
		(net "M_C_CPU1_SB_DQS_DN<7>")
	)
	(segment
		(start 90.687906 -229.765606)
		(end 90.682064 -229.762304)
		(width 0.088646)
		(layer "In4.Cu")
		(net "M_C_CPU1_SB_DQS_DN<7>")
	)
	(segment
		(start 49.986946 -210.224116)
		(end 49.114456 -211.096606)
		(width 0.18288)
		(layer "In4.Cu")
		(net "M_C_CPU1_SB_DQS_DN<7>")
	)
	(segment
		(start 65.54597 -211.149184)
		(end 64.99733 -211.149184)
		(width 0.18288)
		(layer "In4.Cu")
		(net "M_C_CPU1_SB_DQS_DN<7>")
	)
	(segment
		(start 90.682064 -229.762304)
		(end 90.676222 -229.758748)
		(width 0.088646)
		(layer "In4.Cu")
		(net "M_C_CPU1_SB_DQS_DN<7>")
	)
	(segment
		(start 83.071716 -228.603048)
		(end 82.791808 -228.603048)
		(width 0.088646)
		(layer "In4.Cu")
		(net "M_C_CPU1_SB_DQS_DN<7>")
	)
	(segment
		(start 62.372748 -210.248754)
		(end 62.372748 -210.072732)
		(width 0.18288)
		(layer "In4.Cu")
		(net "M_C_CPU1_SB_DQS_DN<7>")
	)
	(segment
		(start 82.791808 -228.603048)
		(end 82.731864 -228.662992)
		(width 0.088646)
		(layer "In4.Cu")
		(net "M_C_CPU1_SB_DQS_DN<7>")
	)
	(segment
		(start 42.290746 -209.606388)
		(end 41.903904 -209.219546)
		(width 0.18288)
		(layer "In4.Cu")
		(net "M_C_CPU1_SB_DQS_DN<7>")
	)
	(segment
		(start 55.24627 -210.2231)
		(end 51.520344 -210.2231)
		(width 0.18288)
		(layer "In4.Cu")
		(net "M_C_CPU1_SB_DQS_DN<7>")
	)
	(segment
		(start 47.150528 -211.34197)
		(end 46.772576 -211.34197)
		(width 0.18288)
		(layer "In4.Cu")
		(net "M_C_CPU1_SB_DQS_DN<7>")
	)
	(segment
		(start 86.548214 -229.762304)
		(end 86.533482 -229.77094)
		(width 0.088646)
		(layer "In4.Cu")
		(net "M_C_CPU1_SB_DQS_DN<7>")
	)
	(segment
		(start 62.76086 -210.636866)
		(end 62.372748 -210.248754)
		(width 0.18288)
		(layer "In4.Cu")
		(net "M_C_CPU1_SB_DQS_DN<7>")
	)
	(segment
		(start 61.930534 -209.630518)
		(end 55.838852 -209.630518)
		(width 0.18288)
		(layer "In4.Cu")
		(net "M_C_CPU1_SB_DQS_DN<7>")
	)
	(segment
		(start 66.21907 -211.024724)
		(end 65.67043 -211.024724)
		(width 0.18288)
		(layer "In4.Cu")
		(net "M_C_CPU1_SB_DQS_DN<7>")
	)
	(segment
		(start 50.602896 -210.224116)
		(end 49.986946 -210.224116)
		(width 0.18288)
		(layer "In4.Cu")
		(net "M_C_CPU1_SB_DQS_DN<7>")
	)
	(segment
		(start 88.427814 -229.762304)
		(end 88.413082 -229.77094)
		(width 0.088646)
		(layer "In4.Cu")
		(net "M_C_CPU1_SB_DQS_DN<7>")
	)
	(segment
		(start 84.386674 -229.837996)
		(end 84.142072 -229.837996)
		(width 0.088646)
		(layer "In4.Cu")
		(net "M_C_CPU1_SB_DQS_DN<7>")
	)
	(segment
		(start 82.731864 -228.662992)
		(end 82.708496 -228.662992)
		(width 0.088646)
		(layer "In4.Cu")
		(net "M_C_CPU1_SB_DQS_DN<7>")
	)
	(segment
		(start 50.870612 -210.491832)
		(end 50.602896 -210.224116)
		(width 0.18288)
		(layer "In4.Cu")
		(net "M_C_CPU1_SB_DQS_DN<7>")
	)
	(segment
		(start 36.255452 -208.938114)
		(end 35.976814 -209.216752)
		(width 0.18288)
		(layer "In4.Cu")
		(net "M_C_CPU1_SB_DQS_DN<7>")
	)
	(segment
		(start 51.251612 -210.491832)
		(end 50.870612 -210.491832)
		(width 0.18288)
		(layer "In4.Cu")
		(net "M_C_CPU1_SB_DQS_DN<7>")
	)
	(segment
		(start 88.803988 -229.763066)
		(end 88.802464 -229.762304)
		(width 0.088646)
		(layer "In4.Cu")
		(net "M_C_CPU1_SB_DQS_DN<7>")
	)
	(segment
		(start 85.608414 -229.762304)
		(end 85.593682 -229.77094)
		(width 0.088646)
		(layer "In4.Cu")
		(net "M_C_CPU1_SB_DQS_DN<7>")
	)
	(segment
		(start 36.660328 -208.938114)
		(end 36.255452 -208.938114)
		(width 0.18288)
		(layer "In4.Cu")
		(net "M_C_CPU1_SB_DQS_DN<7>")
	)
	(segment
		(start 47.395892 -211.096606)
		(end 47.150528 -211.34197)
		(width 0.18288)
		(layer "In4.Cu")
		(net "M_C_CPU1_SB_DQS_DN<7>")
	)
	(segment
		(start 91.627706 -229.765606)
		(end 91.621864 -229.762304)
		(width 0.088646)
		(layer "In4.Cu")
		(net "M_C_CPU1_SB_DQS_DN<7>")
	)
	(segment
		(start 63.32474 -211.024724)
		(end 62.936882 -210.636866)
		(width 0.18288)
		(layer "In4.Cu")
		(net "M_C_CPU1_SB_DQS_DN<7>")
	)
	(segment
		(start 51.520344 -210.2231)
		(end 51.251612 -210.491832)
		(width 0.18288)
		(layer "In4.Cu")
		(net "M_C_CPU1_SB_DQS_DN<7>")
	)
	(segment
		(start 83.186778 -228.882702)
		(end 83.186778 -228.71811)
		(width 0.088646)
		(layer "In4.Cu")
		(net "M_C_CPU1_SB_DQS_DN<7>")
	)
	(segment
		(start 84.668614 -229.762304)
		(end 84.668614 -229.76205)
		(width 0.088646)
		(layer "In4.Cu")
		(net "M_C_CPU1_SB_DQS_DN<7>")
	)
	(segment
		(start 93.62694 -230.086662)
		(end 93.68409 -230.029512)
		(width 0.088646)
		(layer "In4.Cu")
		(net "M_C_CPU1_SB_DQS_DN<7>")
	)
	(segment
		(start 87.488014 -229.762304)
		(end 87.473282 -229.77094)
		(width 0.088646)
		(layer "In4.Cu")
		(net "M_C_CPU1_SB_DQS_DN<7>")
	)
	(segment
		(start 62.372748 -210.072732)
		(end 61.930534 -209.630518)
		(width 0.18288)
		(layer "In4.Cu")
		(net "M_C_CPU1_SB_DQS_DN<7>")
	)
	(segment
		(start 46.772576 -211.34197)
		(end 46.473872 -211.043266)
		(width 0.18288)
		(layer "In4.Cu")
		(net "M_C_CPU1_SB_DQS_DN<7>")
	)
	(segment
		(start 41.903904 -209.219546)
		(end 36.94176 -209.219546)
		(width 0.18288)
		(layer "In4.Cu")
		(net "M_C_CPU1_SB_DQS_DN<7>")
	)
	(segment
		(start 91.621864 -229.762304)
		(end 91.616022 -229.758748)
		(width 0.088646)
		(layer "In4.Cu")
		(net "M_C_CPU1_SB_DQS_DN<7>")
	)
	(segment
		(start 82.708496 -228.662992)
		(end 77.915262 -228.662992)
		(width 0.18288)
		(layer "In4.Cu")
		(net "M_C_CPU1_SB_DQS_DN<7>")
	)
	(segment
		(start 44.26966 -209.606388)
		(end 42.290746 -209.606388)
		(width 0.18288)
		(layer "In4.Cu")
		(net "M_C_CPU1_SB_DQS_DN<7>")
	)
	(segment
		(start 84.142072 -229.837996)
		(end 83.186778 -228.882702)
		(width 0.088646)
		(layer "In4.Cu")
		(net "M_C_CPU1_SB_DQS_DN<7>")
	)
	(segment
		(start 65.67043 -211.024724)
		(end 65.54597 -211.149184)
		(width 0.18288)
		(layer "In4.Cu")
		(net "M_C_CPU1_SB_DQS_DN<7>")
	)
	(segment
		(start 77.915262 -228.662992)
		(end 71.458074 -222.205804)
		(width 0.18288)
		(layer "In4.Cu")
		(net "M_C_CPU1_SB_DQS_DN<7>")
	)
	(segment
		(start 46.473872 -211.043266)
		(end 45.706538 -211.043266)
		(width 0.18288)
		(layer "In4.Cu")
		(net "M_C_CPU1_SB_DQS_DN<7>")
	)
	(segment
		(start 89.742264 -229.762304)
		(end 89.736422 -229.758748)
		(width 0.088646)
		(layer "In4.Cu")
		(net "M_C_CPU1_SB_DQS_DN<7>")
	)
	(segment
		(start 88.802464 -229.762304)
		(end 88.798654 -229.760018)
		(width 0.088646)
		(layer "In4.Cu")
		(net "M_C_CPU1_SB_DQS_DN<7>")
	)
	(segment
		(start 55.838852 -209.630518)
		(end 55.24627 -210.2231)
		(width 0.18288)
		(layer "In4.Cu")
		(net "M_C_CPU1_SB_DQS_DN<7>")
	)
	(segment
		(start 62.936882 -210.636866)
		(end 62.76086 -210.636866)
		(width 0.18288)
		(layer "In4.Cu")
		(net "M_C_CPU1_SB_DQS_DN<7>")
	)
	(segment
		(start 83.186778 -228.71811)
		(end 83.071716 -228.603048)
		(width 0.088646)
		(layer "In4.Cu")
		(net "M_C_CPU1_SB_DQS_DN<7>")
	)
	(segment
		(start 93.314012 -230.086662)
		(end 93.62694 -230.086662)
		(width 0.088646)
		(layer "In4.Cu")
		(net "M_C_CPU1_SB_DQS_DN<7>")
	)
	(segment
		(start 36.94176 -209.219546)
		(end 36.660328 -208.938114)
		(width 0.18288)
		(layer "In4.Cu")
		(net "M_C_CPU1_SB_DQS_DN<7>")
	)
	(segment
		(start 88.808306 -229.765606)
		(end 88.803988 -229.763066)
		(width 0.088646)
		(layer "In4.Cu")
		(net "M_C_CPU1_SB_DQS_DN<7>")
	)
	(segment
		(start 67.25285 -212.058504)
		(end 66.21907 -211.024724)
		(width 0.18288)
		(layer "In4.Cu")
		(net "M_C_CPU1_SB_DQS_DN<7>")
	)
	(segment
		(start 93.126814 -229.762304)
		(end 93.112082 -229.77094)
		(width 0.088646)
		(layer "In4.Cu")
		(net "M_C_CPU1_SB_DQS_DN<7>")
	)
	(segment
		(start 89.748106 -229.765606)
		(end 89.742264 -229.762304)
		(width 0.088646)
		(layer "In4.Cu")
		(net "M_C_CPU1_SB_DQS_DN<7>")
	)
	(segment
		(start 45.706538 -211.043266)
		(end 44.26966 -209.606388)
		(width 0.18288)
		(layer "In4.Cu")
		(net "M_C_CPU1_SB_DQS_DN<7>")
	)
	(segment
		(start 49.114456 -211.096606)
		(end 47.395892 -211.096606)
		(width 0.18288)
		(layer "In4.Cu")
		(net "M_C_CPU1_SB_DQS_DN<7>")
	)
	(arc
		(start 87.473282 -229.77094)
		(mid 87.196807 -229.83826)
		(end 86.92261 -229.762304)
		(width 0.088646)
		(layer "In4.Cu")
		(net "M_C_CPU1_SB_DQS_DN<7>")
	)
	(arc
		(start 89.736422 -229.758748)
		(mid 89.551537 -229.711955)
		(end 89.367614 -229.762304)
		(width 0.088646)
		(layer "In4.Cu")
		(net "M_C_CPU1_SB_DQS_DN<7>")
	)
	(arc
		(start 92.56141 -229.762304)
		(mid 92.374212 -229.712161)
		(end 92.187014 -229.762304)
		(width 0.088646)
		(layer "In4.Cu")
		(net "M_C_CPU1_SB_DQS_DN<7>")
	)
	(arc
		(start 85.04301 -229.762304)
		(mid 84.855812 -229.712161)
		(end 84.668614 -229.762304)
		(width 0.088646)
		(layer "In4.Cu")
		(net "M_C_CPU1_SB_DQS_DN<7>")
	)
	(arc
		(start 85.593682 -229.77094)
		(mid 85.317207 -229.83826)
		(end 85.04301 -229.762304)
		(width 0.088646)
		(layer "In4.Cu")
		(net "M_C_CPU1_SB_DQS_DN<7>")
	)
	(arc
		(start 88.798654 -229.760018)
		(mid 88.612935 -229.712066)
		(end 88.427814 -229.762304)
		(width 0.088646)
		(layer "In4.Cu")
		(net "M_C_CPU1_SB_DQS_DN<7>")
	)
	(arc
		(start 91.247214 -229.762304)
		(mid 90.968011 -229.837944)
		(end 90.687906 -229.765606)
		(width 0.088646)
		(layer "In4.Cu")
		(net "M_C_CPU1_SB_DQS_DN<7>")
	)
	(arc
		(start 91.616022 -229.758748)
		(mid 91.431137 -229.711955)
		(end 91.247214 -229.762304)
		(width 0.088646)
		(layer "In4.Cu")
		(net "M_C_CPU1_SB_DQS_DN<7>")
	)
	(arc
		(start 92.187014 -229.762304)
		(mid 91.907811 -229.837944)
		(end 91.627706 -229.765606)
		(width 0.088646)
		(layer "In4.Cu")
		(net "M_C_CPU1_SB_DQS_DN<7>")
	)
	(arc
		(start 93.112082 -229.77094)
		(mid 92.835607 -229.83826)
		(end 92.56141 -229.762304)
		(width 0.088646)
		(layer "In4.Cu")
		(net "M_C_CPU1_SB_DQS_DN<7>")
	)
	(arc
		(start 86.533482 -229.77094)
		(mid 86.257007 -229.83826)
		(end 85.98281 -229.762304)
		(width 0.088646)
		(layer "In4.Cu")
		(net "M_C_CPU1_SB_DQS_DN<7>")
	)
	(arc
		(start 93.68409 -230.029512)
		(mid 93.475903 -229.749001)
		(end 93.126814 -229.762304)
		(width 0.088646)
		(layer "In4.Cu")
		(net "M_C_CPU1_SB_DQS_DN<7>")
	)
	(arc
		(start 88.413082 -229.77094)
		(mid 88.136607 -229.83826)
		(end 87.86241 -229.762304)
		(width 0.088646)
		(layer "In4.Cu")
		(net "M_C_CPU1_SB_DQS_DN<7>")
	)
	(arc
		(start 86.92261 -229.762304)
		(mid 86.735412 -229.712161)
		(end 86.548214 -229.762304)
		(width 0.088646)
		(layer "In4.Cu")
		(net "M_C_CPU1_SB_DQS_DN<7>")
	)
	(arc
		(start 87.86241 -229.762304)
		(mid 87.675212 -229.712161)
		(end 87.488014 -229.762304)
		(width 0.088646)
		(layer "In4.Cu")
		(net "M_C_CPU1_SB_DQS_DN<7>")
	)
	(arc
		(start 89.367614 -229.762304)
		(mid 89.088411 -229.837944)
		(end 88.808306 -229.765606)
		(width 0.088646)
		(layer "In4.Cu")
		(net "M_C_CPU1_SB_DQS_DN<7>")
	)
	(arc
		(start 90.676222 -229.758748)
		(mid 90.491337 -229.711955)
		(end 90.307414 -229.762304)
		(width 0.088646)
		(layer "In4.Cu")
		(net "M_C_CPU1_SB_DQS_DN<7>")
	)
	(arc
		(start 85.98281 -229.762304)
		(mid 85.795612 -229.712161)
		(end 85.608414 -229.762304)
		(width 0.088646)
		(layer "In4.Cu")
		(net "M_C_CPU1_SB_DQS_DN<7>")
	)
	(arc
		(start 90.307414 -229.762304)
		(mid 90.028211 -229.837944)
		(end 89.748106 -229.765606)
		(width 0.088646)
		(layer "In4.Cu")
		(net "M_C_CPU1_SB_DQS_DN<7>")
	)
	(arc
		(start 84.668614 -229.76205)
		(mid 84.532637 -229.818566)
		(end 84.386674 -229.837996)
		(width 0.088646)
		(layer "In4.Cu")
		(net "M_C_CPU1_SB_DQS_DN<7>")
	)
	(segment
		(start 32.114998 -218.141804)
		(end 32.37611 -217.880692)
		(width 0.20066)
		(layer "F.Cu")
		(net "M_C_CPU1_SB_DQS_DN<6>")
	)
	(segment
		(start 29.647642 -218.149678)
		(end 29.655516 -218.141804)
		(width 0.101854)
		(layer "F.Cu")
		(net "M_C_CPU1_SB_DQS_DN<6>")
	)
	(segment
		(start 29.46273 -218.149678)
		(end 29.647642 -218.149678)
		(width 0.20066)
		(layer "F.Cu")
		(net "M_C_CPU1_SB_DQS_DN<6>")
	)
	(segment
		(start 28.534106 -218.305634)
		(end 28.956508 -217.883232)
		(width 0.20066)
		(layer "F.Cu")
		(net "M_C_CPU1_SB_DQS_DN<6>")
	)
	(segment
		(start 34.38144 -218.566746)
		(end 34.871914 -218.566746)
		(width 0.20066)
		(layer "F.Cu")
		(net "M_C_CPU1_SB_DQS_DN<6>")
	)
	(segment
		(start 31.972758 -218.141804)
		(end 32.114998 -218.141804)
		(width 0.20066)
		(layer "F.Cu")
		(net "M_C_CPU1_SB_DQS_DN<6>")
	)
	(segment
		(start 29.895292 -218.141804)
		(end 31.972758 -218.141804)
		(width 0.1016)
		(layer "F.Cu")
		(net "M_C_CPU1_SB_DQS_DN<6>")
	)
	(segment
		(start 33.416748 -218.305634)
		(end 34.120328 -218.305634)
		(width 0.20066)
		(layer "F.Cu")
		(net "M_C_CPU1_SB_DQS_DN<6>")
	)
	(segment
		(start 28.956508 -217.883232)
		(end 29.196284 -217.883232)
		(width 0.20066)
		(layer "F.Cu")
		(net "M_C_CPU1_SB_DQS_DN<6>")
	)
	(segment
		(start 34.120328 -218.305634)
		(end 34.38144 -218.566746)
		(width 0.20066)
		(layer "F.Cu")
		(net "M_C_CPU1_SB_DQS_DN<6>")
	)
	(segment
		(start 35.976814 -218.566746)
		(end 34.871914 -218.566746)
		(width 0.20066)
		(layer "F.Cu")
		(net "M_C_CPU1_SB_DQS_DN<6>")
	)
	(segment
		(start 96.603312 -237.947454)
		(end 96.603566 -237.9472)
		(width 0.20066)
		(layer "F.Cu")
		(net "M_C_CPU1_SB_DQS_DN<6>")
	)
	(segment
		(start 32.37611 -217.880692)
		(end 32.780732 -217.880692)
		(width 0.20066)
		(layer "F.Cu")
		(net "M_C_CPU1_SB_DQS_DN<6>")
	)
	(segment
		(start 28.060904 -218.305634)
		(end 28.534106 -218.305634)
		(width 0.20066)
		(layer "F.Cu")
		(net "M_C_CPU1_SB_DQS_DN<6>")
	)
	(segment
		(start 32.780732 -217.880692)
		(end 33.416748 -218.305634)
		(width 0.20066)
		(layer "F.Cu")
		(net "M_C_CPU1_SB_DQS_DN<6>")
	)
	(segment
		(start 29.196284 -217.883232)
		(end 29.46273 -218.149678)
		(width 0.20066)
		(layer "F.Cu")
		(net "M_C_CPU1_SB_DQS_DN<6>")
	)
	(segment
		(start 27.799792 -218.566746)
		(end 28.060904 -218.305634)
		(width 0.20066)
		(layer "F.Cu")
		(net "M_C_CPU1_SB_DQS_DN<6>")
	)
	(segment
		(start 27.328114 -218.566746)
		(end 27.799792 -218.566746)
		(width 0.20066)
		(layer "F.Cu")
		(net "M_C_CPU1_SB_DQS_DN<6>")
	)
	(segment
		(start 29.655516 -218.141804)
		(end 29.895292 -218.141804)
		(width 0.101854)
		(layer "F.Cu")
		(net "M_C_CPU1_SB_DQS_DN<6>")
	)
	(segment
		(start 96.603566 -237.9472)
		(end 96.603566 -237.411514)
		(width 0.20066)
		(layer "F.Cu")
		(net "M_C_CPU1_SB_DQS_DN<6>")
	)
	(segment
		(start 86.170516 -236.607858)
		(end 86.170516 -236.597952)
		(width 0.088646)
		(layer "In6.Cu")
		(net "M_C_CPU1_SB_DQS_DN<6>")
	)
	(segment
		(start 66.370454 -224.942146)
		(end 65.959482 -224.942146)
		(width 0.18288)
		(layer "In6.Cu")
		(net "M_C_CPU1_SB_DQS_DN<6>")
	)
	(segment
		(start 55.088282 -221.25432)
		(end 51.596544 -221.25432)
		(width 0.18288)
		(layer "In6.Cu")
		(net "M_C_CPU1_SB_DQS_DN<6>")
	)
	(segment
		(start 55.784496 -220.558106)
		(end 55.088282 -221.25432)
		(width 0.18288)
		(layer "In6.Cu")
		(net "M_C_CPU1_SB_DQS_DN<6>")
	)
	(segment
		(start 51.308508 -221.542356)
		(end 50.846736 -221.542356)
		(width 0.18288)
		(layer "In6.Cu")
		(net "M_C_CPU1_SB_DQS_DN<6>")
	)
	(segment
		(start 58.016648 -220.558106)
		(end 57.892188 -220.682566)
		(width 0.18288)
		(layer "In6.Cu")
		(net "M_C_CPU1_SB_DQS_DN<6>")
	)
	(segment
		(start 83.85048 -235.656374)
		(end 83.139026 -234.94492)
		(width 0.088646)
		(layer "In6.Cu")
		(net "M_C_CPU1_SB_DQS_DN<6>")
	)
	(segment
		(start 87.018114 -237.08741)
		(end 87.0077 -237.093506)
		(width 0.088646)
		(layer "In6.Cu")
		(net "M_C_CPU1_SB_DQS_DN<6>")
	)
	(segment
		(start 36.775644 -218.539314)
		(end 36.54552 -218.30919)
		(width 0.18288)
		(layer "In6.Cu")
		(net "M_C_CPU1_SB_DQS_DN<6>")
	)
	(segment
		(start 47.206408 -220.69171)
		(end 46.72838 -220.69171)
		(width 0.18288)
		(layer "In6.Cu")
		(net "M_C_CPU1_SB_DQS_DN<6>")
	)
	(segment
		(start 66.955416 -224.705926)
		(end 66.606674 -224.705926)
		(width 0.18288)
		(layer "In6.Cu")
		(net "M_C_CPU1_SB_DQS_DN<6>")
	)
	(segment
		(start 84.181442 -236.34954)
		(end 83.85048 -236.018578)
		(width 0.088646)
		(layer "In6.Cu")
		(net "M_C_CPU1_SB_DQS_DN<6>")
	)
	(segment
		(start 89.287096 -237.096046)
		(end 89.272364 -237.08741)
		(width 0.088646)
		(layer "In6.Cu")
		(net "M_C_CPU1_SB_DQS_DN<6>")
	)
	(segment
		(start 36.23437 -218.30919)
		(end 35.976814 -218.566746)
		(width 0.18288)
		(layer "In6.Cu")
		(net "M_C_CPU1_SB_DQS_DN<6>")
	)
	(segment
		(start 49.127664 -220.411802)
		(end 47.486316 -220.411802)
		(width 0.18288)
		(layer "In6.Cu")
		(net "M_C_CPU1_SB_DQS_DN<6>")
	)
	(segment
		(start 36.54552 -218.30919)
		(end 36.23437 -218.30919)
		(width 0.18288)
		(layer "In6.Cu")
		(net "M_C_CPU1_SB_DQS_DN<6>")
	)
	(segment
		(start 42.98315 -220.32468)
		(end 41.61409 -218.95562)
		(width 0.18288)
		(layer "In6.Cu")
		(net "M_C_CPU1_SB_DQS_DN<6>")
	)
	(segment
		(start 82.858864 -234.702604)
		(end 82.835496 -234.702604)
		(width 0.088646)
		(layer "In6.Cu")
		(net "M_C_CPU1_SB_DQS_DN<6>")
	)
	(segment
		(start 41.61409 -218.95562)
		(end 40.679116 -218.95562)
		(width 0.18288)
		(layer "In6.Cu")
		(net "M_C_CPU1_SB_DQS_DN<6>")
	)
	(segment
		(start 39.675308 -218.539314)
		(end 36.775644 -218.539314)
		(width 0.18288)
		(layer "In6.Cu")
		(net "M_C_CPU1_SB_DQS_DN<6>")
	)
	(segment
		(start 95.865696 -237.096046)
		(end 95.850964 -237.08741)
		(width 0.088646)
		(layer "In6.Cu")
		(net "M_C_CPU1_SB_DQS_DN<6>")
	)
	(segment
		(start 61.105034 -221.64675)
		(end 60.556394 -221.64675)
		(width 0.18288)
		(layer "In6.Cu")
		(net "M_C_CPU1_SB_DQS_DN<6>")
	)
	(segment
		(start 65.703196 -224.68586)
		(end 64.77 -224.68586)
		(width 0.18288)
		(layer "In6.Cu")
		(net "M_C_CPU1_SB_DQS_DN<6>")
	)
	(segment
		(start 83.139026 -234.94492)
		(end 83.139026 -234.746546)
		(width 0.088646)
		(layer "In6.Cu")
		(net "M_C_CPU1_SB_DQS_DN<6>")
	)
	(segment
		(start 40.679116 -218.95562)
		(end 39.675308 -218.539314)
		(width 0.18288)
		(layer "In6.Cu")
		(net "M_C_CPU1_SB_DQS_DN<6>")
	)
	(segment
		(start 45.08373 -219.714318)
		(end 44.554394 -219.714318)
		(width 0.18288)
		(layer "In6.Cu")
		(net "M_C_CPU1_SB_DQS_DN<6>")
	)
	(segment
		(start 82.918554 -234.642914)
		(end 82.858864 -234.702604)
		(width 0.088646)
		(layer "In6.Cu")
		(net "M_C_CPU1_SB_DQS_DN<6>")
	)
	(segment
		(start 90.226896 -237.096046)
		(end 90.212164 -237.08741)
		(width 0.088646)
		(layer "In6.Cu")
		(net "M_C_CPU1_SB_DQS_DN<6>")
	)
	(segment
		(start 83.139026 -234.746546)
		(end 83.035394 -234.642914)
		(width 0.088646)
		(layer "In6.Cu")
		(net "M_C_CPU1_SB_DQS_DN<6>")
	)
	(segment
		(start 51.596544 -221.25432)
		(end 51.308508 -221.542356)
		(width 0.18288)
		(layer "In6.Cu")
		(net "M_C_CPU1_SB_DQS_DN<6>")
	)
	(segment
		(start 63.310516 -223.22663)
		(end 62.711584 -221.781878)
		(width 0.18288)
		(layer "In6.Cu")
		(net "M_C_CPU1_SB_DQS_DN<6>")
	)
	(segment
		(start 49.96434 -221.248478)
		(end 49.127664 -220.411802)
		(width 0.18288)
		(layer "In6.Cu")
		(net "M_C_CPU1_SB_DQS_DN<6>")
	)
	(segment
		(start 61.229494 -221.52229)
		(end 61.105034 -221.64675)
		(width 0.18288)
		(layer "In6.Cu")
		(net "M_C_CPU1_SB_DQS_DN<6>")
	)
	(segment
		(start 96.916494 -237.411514)
		(end 96.973644 -237.354364)
		(width 0.088646)
		(layer "In6.Cu")
		(net "M_C_CPU1_SB_DQS_DN<6>")
	)
	(segment
		(start 96.603566 -237.411514)
		(end 96.916494 -237.411514)
		(width 0.088646)
		(layer "In6.Cu")
		(net "M_C_CPU1_SB_DQS_DN<6>")
	)
	(segment
		(start 47.486316 -220.411802)
		(end 47.206408 -220.69171)
		(width 0.18288)
		(layer "In6.Cu")
		(net "M_C_CPU1_SB_DQS_DN<6>")
	)
	(segment
		(start 46.44263 -220.40596)
		(end 45.775372 -220.40596)
		(width 0.18288)
		(layer "In6.Cu")
		(net "M_C_CPU1_SB_DQS_DN<6>")
	)
	(segment
		(start 92.101924 -237.093506)
		(end 92.09151 -237.08741)
		(width 0.088646)
		(layer "In6.Cu")
		(net "M_C_CPU1_SB_DQS_DN<6>")
	)
	(segment
		(start 87.958168 -237.08741)
		(end 87.947754 -237.093506)
		(width 0.088646)
		(layer "In6.Cu")
		(net "M_C_CPU1_SB_DQS_DN<6>")
	)
	(segment
		(start 57.343548 -220.682566)
		(end 57.219088 -220.558106)
		(width 0.18288)
		(layer "In6.Cu")
		(net "M_C_CPU1_SB_DQS_DN<6>")
	)
	(segment
		(start 65.959482 -224.942146)
		(end 65.703196 -224.68586)
		(width 0.18288)
		(layer "In6.Cu")
		(net "M_C_CPU1_SB_DQS_DN<6>")
	)
	(segment
		(start 58.660538 -220.558106)
		(end 58.016648 -220.558106)
		(width 0.18288)
		(layer "In6.Cu")
		(net "M_C_CPU1_SB_DQS_DN<6>")
	)
	(segment
		(start 83.85048 -236.018578)
		(end 83.85048 -235.656374)
		(width 0.088646)
		(layer "In6.Cu")
		(net "M_C_CPU1_SB_DQS_DN<6>")
	)
	(segment
		(start 60.556394 -221.64675)
		(end 60.431934 -221.52229)
		(width 0.18288)
		(layer "In6.Cu")
		(net "M_C_CPU1_SB_DQS_DN<6>")
	)
	(segment
		(start 82.835496 -234.702604)
		(end 74.78395 -234.702604)
		(width 0.18288)
		(layer "In6.Cu")
		(net "M_C_CPU1_SB_DQS_DN<6>")
	)
	(segment
		(start 94.925896 -237.096046)
		(end 94.911164 -237.08741)
		(width 0.088646)
		(layer "In6.Cu")
		(net "M_C_CPU1_SB_DQS_DN<6>")
	)
	(segment
		(start 43.944032 -220.32468)
		(end 42.98315 -220.32468)
		(width 0.18288)
		(layer "In6.Cu")
		(net "M_C_CPU1_SB_DQS_DN<6>")
	)
	(segment
		(start 91.162378 -237.093506)
		(end 91.151964 -237.08741)
		(width 0.088646)
		(layer "In6.Cu")
		(net "M_C_CPU1_SB_DQS_DN<6>")
	)
	(segment
		(start 93.046296 -237.096046)
		(end 93.031564 -237.08741)
		(width 0.088646)
		(layer "In6.Cu")
		(net "M_C_CPU1_SB_DQS_DN<6>")
	)
	(segment
		(start 85.608668 -236.273594)
		(end 85.593936 -236.28223)
		(width 0.088646)
		(layer "In6.Cu")
		(net "M_C_CPU1_SB_DQS_DN<6>")
	)
	(segment
		(start 68.21043 -225.959416)
		(end 66.955416 -224.705926)
		(width 0.18288)
		(layer "In6.Cu")
		(net "M_C_CPU1_SB_DQS_DN<6>")
	)
	(segment
		(start 64.77 -224.68586)
		(end 63.310516 -223.22663)
		(width 0.18288)
		(layer "In6.Cu")
		(net "M_C_CPU1_SB_DQS_DN<6>")
	)
	(segment
		(start 50.552858 -221.248478)
		(end 49.96434 -221.248478)
		(width 0.18288)
		(layer "In6.Cu")
		(net "M_C_CPU1_SB_DQS_DN<6>")
	)
	(segment
		(start 45.775372 -220.40596)
		(end 45.08373 -219.714318)
		(width 0.18288)
		(layer "In6.Cu")
		(net "M_C_CPU1_SB_DQS_DN<6>")
	)
	(segment
		(start 57.892188 -220.682566)
		(end 57.343548 -220.682566)
		(width 0.18288)
		(layer "In6.Cu")
		(net "M_C_CPU1_SB_DQS_DN<6>")
	)
	(segment
		(start 83.035394 -234.642914)
		(end 82.918554 -234.642914)
		(width 0.088646)
		(layer "In6.Cu")
		(net "M_C_CPU1_SB_DQS_DN<6>")
	)
	(segment
		(start 62.085474 -221.52229)
		(end 61.229494 -221.52229)
		(width 0.18288)
		(layer "In6.Cu")
		(net "M_C_CPU1_SB_DQS_DN<6>")
	)
	(segment
		(start 74.78395 -234.702604)
		(end 68.21043 -228.129084)
		(width 0.18288)
		(layer "In6.Cu")
		(net "M_C_CPU1_SB_DQS_DN<6>")
	)
	(segment
		(start 62.711584 -221.781878)
		(end 62.085474 -221.52229)
		(width 0.18288)
		(layer "In6.Cu")
		(net "M_C_CPU1_SB_DQS_DN<6>")
	)
	(segment
		(start 66.606674 -224.705926)
		(end 66.370454 -224.942146)
		(width 0.18288)
		(layer "In6.Cu")
		(net "M_C_CPU1_SB_DQS_DN<6>")
	)
	(segment
		(start 84.385912 -236.34954)
		(end 84.181442 -236.34954)
		(width 0.088646)
		(layer "In6.Cu")
		(net "M_C_CPU1_SB_DQS_DN<6>")
	)
	(segment
		(start 50.846736 -221.542356)
		(end 50.552858 -221.248478)
		(width 0.18288)
		(layer "In6.Cu")
		(net "M_C_CPU1_SB_DQS_DN<6>")
	)
	(segment
		(start 60.431934 -221.52229)
		(end 59.624722 -221.52229)
		(width 0.18288)
		(layer "In6.Cu")
		(net "M_C_CPU1_SB_DQS_DN<6>")
	)
	(segment
		(start 46.72838 -220.69171)
		(end 46.44263 -220.40596)
		(width 0.18288)
		(layer "In6.Cu")
		(net "M_C_CPU1_SB_DQS_DN<6>")
	)
	(segment
		(start 59.624722 -221.52229)
		(end 58.660538 -220.558106)
		(width 0.18288)
		(layer "In6.Cu")
		(net "M_C_CPU1_SB_DQS_DN<6>")
	)
	(segment
		(start 68.21043 -228.129084)
		(end 68.21043 -225.959416)
		(width 0.18288)
		(layer "In6.Cu")
		(net "M_C_CPU1_SB_DQS_DN<6>")
	)
	(segment
		(start 44.554394 -219.714318)
		(end 43.944032 -220.32468)
		(width 0.18288)
		(layer "In6.Cu")
		(net "M_C_CPU1_SB_DQS_DN<6>")
	)
	(segment
		(start 57.219088 -220.558106)
		(end 55.784496 -220.558106)
		(width 0.18288)
		(layer "In6.Cu")
		(net "M_C_CPU1_SB_DQS_DN<6>")
	)
	(arc
		(start 85.593936 -236.28223)
		(mid 85.317461 -236.34955)
		(end 85.043264 -236.273594)
		(width 0.088646)
		(layer "In6.Cu")
		(net "M_C_CPU1_SB_DQS_DN<6>")
	)
	(arc
		(start 84.668868 -236.273594)
		(mid 84.532396 -236.330217)
		(end 84.385912 -236.34954)
		(width 0.088646)
		(layer "In6.Cu")
		(net "M_C_CPU1_SB_DQS_DN<6>")
	)
	(arc
		(start 96.416368 -237.08741)
		(mid 96.142169 -237.163245)
		(end 95.865696 -237.096046)
		(width 0.088646)
		(layer "In6.Cu")
		(net "M_C_CPU1_SB_DQS_DN<6>")
	)
	(arc
		(start 93.031564 -237.08741)
		(mid 92.844366 -237.037233)
		(end 92.657168 -237.08741)
		(width 0.088646)
		(layer "In6.Cu")
		(net "M_C_CPU1_SB_DQS_DN<6>")
	)
	(arc
		(start 89.837768 -237.08741)
		(mid 89.563569 -237.163245)
		(end 89.287096 -237.096046)
		(width 0.088646)
		(layer "In6.Cu")
		(net "M_C_CPU1_SB_DQS_DN<6>")
	)
	(arc
		(start 89.272364 -237.08741)
		(mid 89.085166 -237.037233)
		(end 88.897968 -237.08741)
		(width 0.088646)
		(layer "In6.Cu")
		(net "M_C_CPU1_SB_DQS_DN<6>")
	)
	(arc
		(start 92.09151 -237.08741)
		(mid 91.904312 -237.037233)
		(end 91.717114 -237.08741)
		(width 0.088646)
		(layer "In6.Cu")
		(net "M_C_CPU1_SB_DQS_DN<6>")
	)
	(arc
		(start 88.332564 -237.08741)
		(mid 88.145366 -237.037233)
		(end 87.958168 -237.08741)
		(width 0.088646)
		(layer "In6.Cu")
		(net "M_C_CPU1_SB_DQS_DN<6>")
	)
	(arc
		(start 87.39251 -237.08741)
		(mid 87.205312 -237.037267)
		(end 87.018114 -237.08741)
		(width 0.088646)
		(layer "In6.Cu")
		(net "M_C_CPU1_SB_DQS_DN<6>")
	)
	(arc
		(start 86.170516 -236.597952)
		(mid 85.983217 -236.273511)
		(end 85.608668 -236.273594)
		(width 0.088646)
		(layer "In6.Cu")
		(net "M_C_CPU1_SB_DQS_DN<6>")
	)
	(arc
		(start 95.850964 -237.08741)
		(mid 95.663766 -237.037233)
		(end 95.476568 -237.08741)
		(width 0.088646)
		(layer "In6.Cu")
		(net "M_C_CPU1_SB_DQS_DN<6>")
	)
	(arc
		(start 92.657168 -237.08741)
		(mid 92.380355 -237.16328)
		(end 92.101924 -237.093506)
		(width 0.088646)
		(layer "In6.Cu")
		(net "M_C_CPU1_SB_DQS_DN<6>")
	)
	(arc
		(start 96.973644 -237.354364)
		(mid 96.7654 -237.073825)
		(end 96.416368 -237.08741)
		(width 0.088646)
		(layer "In6.Cu")
		(net "M_C_CPU1_SB_DQS_DN<6>")
	)
	(arc
		(start 91.151964 -237.08741)
		(mid 90.964766 -237.037233)
		(end 90.777568 -237.08741)
		(width 0.088646)
		(layer "In6.Cu")
		(net "M_C_CPU1_SB_DQS_DN<6>")
	)
	(arc
		(start 88.897968 -237.08741)
		(mid 88.615266 -237.163186)
		(end 88.332564 -237.08741)
		(width 0.088646)
		(layer "In6.Cu")
		(net "M_C_CPU1_SB_DQS_DN<6>")
	)
	(arc
		(start 91.717114 -237.08741)
		(mid 91.440555 -237.163153)
		(end 91.162378 -237.093506)
		(width 0.088646)
		(layer "In6.Cu")
		(net "M_C_CPU1_SB_DQS_DN<6>")
	)
	(arc
		(start 85.043264 -236.273594)
		(mid 84.856066 -236.223451)
		(end 84.668868 -236.273594)
		(width 0.088646)
		(layer "In6.Cu")
		(net "M_C_CPU1_SB_DQS_DN<6>")
	)
	(arc
		(start 87.947754 -237.093506)
		(mid 87.669322 -237.163352)
		(end 87.39251 -237.08741)
		(width 0.088646)
		(layer "In6.Cu")
		(net "M_C_CPU1_SB_DQS_DN<6>")
	)
	(arc
		(start 95.476568 -237.08741)
		(mid 95.202369 -237.163245)
		(end 94.925896 -237.096046)
		(width 0.088646)
		(layer "In6.Cu")
		(net "M_C_CPU1_SB_DQS_DN<6>")
	)
	(arc
		(start 94.536768 -237.08741)
		(mid 94.254066 -237.163186)
		(end 93.971364 -237.08741)
		(width 0.088646)
		(layer "In6.Cu")
		(net "M_C_CPU1_SB_DQS_DN<6>")
	)
	(arc
		(start 94.911164 -237.08741)
		(mid 94.723966 -237.037233)
		(end 94.536768 -237.08741)
		(width 0.088646)
		(layer "In6.Cu")
		(net "M_C_CPU1_SB_DQS_DN<6>")
	)
	(arc
		(start 90.777568 -237.08741)
		(mid 90.503369 -237.163245)
		(end 90.226896 -237.096046)
		(width 0.088646)
		(layer "In6.Cu")
		(net "M_C_CPU1_SB_DQS_DN<6>")
	)
	(arc
		(start 87.0077 -237.093506)
		(mid 86.452023 -237.086954)
		(end 86.170516 -236.607858)
		(width 0.088646)
		(layer "In6.Cu")
		(net "M_C_CPU1_SB_DQS_DN<6>")
	)
	(arc
		(start 93.596968 -237.08741)
		(mid 93.322769 -237.163245)
		(end 93.046296 -237.096046)
		(width 0.088646)
		(layer "In6.Cu")
		(net "M_C_CPU1_SB_DQS_DN<6>")
	)
	(arc
		(start 93.971364 -237.08741)
		(mid 93.784166 -237.037233)
		(end 93.596968 -237.08741)
		(width 0.088646)
		(layer "In6.Cu")
		(net "M_C_CPU1_SB_DQS_DN<6>")
	)
	(arc
		(start 90.212164 -237.08741)
		(mid 90.024966 -237.037233)
		(end 89.837768 -237.08741)
		(width 0.088646)
		(layer "In6.Cu")
		(net "M_C_CPU1_SB_DQS_DN<6>")
	)
	(segment
		(start 31.972758 -227.491798)
		(end 32.114998 -227.491798)
		(width 0.20066)
		(layer "F.Cu")
		(net "M_C_CPU1_SB_DQS_DN<5>")
	)
	(segment
		(start 28.956508 -227.233226)
		(end 29.196284 -227.233226)
		(width 0.20066)
		(layer "F.Cu")
		(net "M_C_CPU1_SB_DQS_DN<5>")
	)
	(segment
		(start 27.799792 -227.91674)
		(end 28.060904 -227.655628)
		(width 0.20066)
		(layer "F.Cu")
		(net "M_C_CPU1_SB_DQS_DN<5>")
	)
	(segment
		(start 28.534106 -227.655628)
		(end 28.956508 -227.233226)
		(width 0.20066)
		(layer "F.Cu")
		(net "M_C_CPU1_SB_DQS_DN<5>")
	)
	(segment
		(start 32.780732 -227.230686)
		(end 33.416748 -227.655628)
		(width 0.20066)
		(layer "F.Cu")
		(net "M_C_CPU1_SB_DQS_DN<5>")
	)
	(segment
		(start 29.895292 -227.491798)
		(end 31.972758 -227.491798)
		(width 0.1016)
		(layer "F.Cu")
		(net "M_C_CPU1_SB_DQS_DN<5>")
	)
	(segment
		(start 34.38144 -227.91674)
		(end 34.871914 -227.91674)
		(width 0.20066)
		(layer "F.Cu")
		(net "M_C_CPU1_SB_DQS_DN<5>")
	)
	(segment
		(start 29.196284 -227.233226)
		(end 29.46273 -227.499672)
		(width 0.20066)
		(layer "F.Cu")
		(net "M_C_CPU1_SB_DQS_DN<5>")
	)
	(segment
		(start 29.647642 -227.499672)
		(end 29.655516 -227.491798)
		(width 0.101854)
		(layer "F.Cu")
		(net "M_C_CPU1_SB_DQS_DN<5>")
	)
	(segment
		(start 33.416748 -227.655628)
		(end 34.120328 -227.655628)
		(width 0.20066)
		(layer "F.Cu")
		(net "M_C_CPU1_SB_DQS_DN<5>")
	)
	(segment
		(start 32.37611 -227.230686)
		(end 32.780732 -227.230686)
		(width 0.20066)
		(layer "F.Cu")
		(net "M_C_CPU1_SB_DQS_DN<5>")
	)
	(segment
		(start 96.603312 -242.830858)
		(end 96.603566 -242.294918)
		(width 0.20066)
		(layer "F.Cu")
		(net "M_C_CPU1_SB_DQS_DN<5>")
	)
	(segment
		(start 29.655516 -227.491798)
		(end 29.895292 -227.491798)
		(width 0.101854)
		(layer "F.Cu")
		(net "M_C_CPU1_SB_DQS_DN<5>")
	)
	(segment
		(start 27.328114 -227.91674)
		(end 27.799792 -227.91674)
		(width 0.20066)
		(layer "F.Cu")
		(net "M_C_CPU1_SB_DQS_DN<5>")
	)
	(segment
		(start 35.976814 -227.91674)
		(end 34.871914 -227.91674)
		(width 0.20066)
		(layer "F.Cu")
		(net "M_C_CPU1_SB_DQS_DN<5>")
	)
	(segment
		(start 28.060904 -227.655628)
		(end 28.534106 -227.655628)
		(width 0.20066)
		(layer "F.Cu")
		(net "M_C_CPU1_SB_DQS_DN<5>")
	)
	(segment
		(start 34.120328 -227.655628)
		(end 34.38144 -227.91674)
		(width 0.20066)
		(layer "F.Cu")
		(net "M_C_CPU1_SB_DQS_DN<5>")
	)
	(segment
		(start 29.46273 -227.499672)
		(end 29.647642 -227.499672)
		(width 0.20066)
		(layer "F.Cu")
		(net "M_C_CPU1_SB_DQS_DN<5>")
	)
	(segment
		(start 32.114998 -227.491798)
		(end 32.37611 -227.230686)
		(width 0.20066)
		(layer "F.Cu")
		(net "M_C_CPU1_SB_DQS_DN<5>")
	)
	(segment
		(start 51.344576 -232.591864)
		(end 50.866548 -232.591864)
		(width 0.18288)
		(layer "In6.Cu")
		(net "M_C_CPU1_SB_DQS_DN<5>")
	)
	(segment
		(start 65.709546 -236.331506)
		(end 64.470026 -235.091986)
		(width 0.18288)
		(layer "In6.Cu")
		(net "M_C_CPU1_SB_DQS_DN<5>")
	)
	(segment
		(start 47.244762 -231.741726)
		(end 46.766226 -231.741726)
		(width 0.18288)
		(layer "In6.Cu")
		(net "M_C_CPU1_SB_DQS_DN<5>")
	)
	(segment
		(start 60.573666 -234.072684)
		(end 60.449206 -233.948224)
		(width 0.18288)
		(layer "In6.Cu")
		(net "M_C_CPU1_SB_DQS_DN<5>")
	)
	(segment
		(start 96.603566 -242.294918)
		(end 96.916494 -242.294918)
		(width 0.088646)
		(layer "In6.Cu")
		(net "M_C_CPU1_SB_DQS_DN<5>")
	)
	(segment
		(start 57.790842 -233.20248)
		(end 57.666382 -233.32694)
		(width 0.18288)
		(layer "In6.Cu")
		(net "M_C_CPU1_SB_DQS_DN<5>")
	)
	(segment
		(start 63.86957 -235.091986)
		(end 62.725808 -233.948224)
		(width 0.18288)
		(layer "In6.Cu")
		(net "M_C_CPU1_SB_DQS_DN<5>")
	)
	(segment
		(start 64.470026 -235.091986)
		(end 63.86957 -235.091986)
		(width 0.18288)
		(layer "In6.Cu")
		(net "M_C_CPU1_SB_DQS_DN<5>")
	)
	(segment
		(start 84.149438 -241.304572)
		(end 83.40344 -240.558574)
		(width 0.088646)
		(layer "In6.Cu")
		(net "M_C_CPU1_SB_DQS_DN<5>")
	)
	(segment
		(start 56.993282 -233.20248)
		(end 55.870602 -233.20248)
		(width 0.18288)
		(layer "In6.Cu")
		(net "M_C_CPU1_SB_DQS_DN<5>")
	)
	(segment
		(start 83.089496 -240.618264)
		(end 71.661782 -240.618264)
		(width 0.18288)
		(layer "In6.Cu")
		(net "M_C_CPU1_SB_DQS_DN<5>")
	)
	(segment
		(start 48.28667 -231.72039)
		(end 48.028352 -231.462072)
		(width 0.18288)
		(layer "In6.Cu")
		(net "M_C_CPU1_SB_DQS_DN<5>")
	)
	(segment
		(start 49.349406 -231.72039)
		(end 48.28667 -231.72039)
		(width 0.18288)
		(layer "In6.Cu")
		(net "M_C_CPU1_SB_DQS_DN<5>")
	)
	(segment
		(start 55.870602 -233.20248)
		(end 55.00243 -232.334308)
		(width 0.18288)
		(layer "In6.Cu")
		(net "M_C_CPU1_SB_DQS_DN<5>")
	)
	(segment
		(start 37.822378 -227.817426)
		(end 36.754816 -227.817426)
		(width 0.18288)
		(layer "In6.Cu")
		(net "M_C_CPU1_SB_DQS_DN<5>")
	)
	(segment
		(start 67.375024 -236.331506)
		(end 65.709546 -236.331506)
		(width 0.18288)
		(layer "In6.Cu")
		(net "M_C_CPU1_SB_DQS_DN<5>")
	)
	(segment
		(start 62.725808 -233.948224)
		(end 61.246766 -233.948224)
		(width 0.18288)
		(layer "In6.Cu")
		(net "M_C_CPU1_SB_DQS_DN<5>")
	)
	(segment
		(start 46.48073 -231.45623)
		(end 45.82541 -231.45623)
		(width 0.18288)
		(layer "In6.Cu")
		(net "M_C_CPU1_SB_DQS_DN<5>")
	)
	(segment
		(start 96.416368 -241.97056)
		(end 96.416114 -241.97056)
		(width 0.088646)
		(layer "In6.Cu")
		(net "M_C_CPU1_SB_DQS_DN<5>")
	)
	(segment
		(start 60.449206 -233.948224)
		(end 59.509152 -233.948224)
		(width 0.18288)
		(layer "In6.Cu")
		(net "M_C_CPU1_SB_DQS_DN<5>")
	)
	(segment
		(start 91.151456 -241.970052)
		(end 91.139518 -241.96294)
		(width 0.088646)
		(layer "In6.Cu")
		(net "M_C_CPU1_SB_DQS_DN<5>")
	)
	(segment
		(start 93.031056 -241.970052)
		(end 93.019118 -241.96294)
		(width 0.088646)
		(layer "In6.Cu")
		(net "M_C_CPU1_SB_DQS_DN<5>")
	)
	(segment
		(start 96.973644 -242.237768)
		(end 96.973898 -242.237768)
		(width 0.088646)
		(layer "In6.Cu")
		(net "M_C_CPU1_SB_DQS_DN<5>")
	)
	(segment
		(start 44.495466 -230.690166)
		(end 43.814746 -230.009446)
		(width 0.18288)
		(layer "In6.Cu")
		(net "M_C_CPU1_SB_DQS_DN<5>")
	)
	(segment
		(start 41.067482 -230.009446)
		(end 40.036496 -228.97846)
		(width 0.18288)
		(layer "In6.Cu")
		(net "M_C_CPU1_SB_DQS_DN<5>")
	)
	(segment
		(start 58.763408 -233.20248)
		(end 57.790842 -233.20248)
		(width 0.18288)
		(layer "In6.Cu")
		(net "M_C_CPU1_SB_DQS_DN<5>")
	)
	(segment
		(start 83.172554 -240.558574)
		(end 83.112864 -240.618264)
		(width 0.088646)
		(layer "In6.Cu")
		(net "M_C_CPU1_SB_DQS_DN<5>")
	)
	(segment
		(start 89.271856 -241.970052)
		(end 89.259918 -241.96294)
		(width 0.088646)
		(layer "In6.Cu")
		(net "M_C_CPU1_SB_DQS_DN<5>")
	)
	(segment
		(start 95.850456 -241.970052)
		(end 95.838518 -241.96294)
		(width 0.088646)
		(layer "In6.Cu")
		(net "M_C_CPU1_SB_DQS_DN<5>")
	)
	(segment
		(start 83.40344 -240.558574)
		(end 83.172554 -240.558574)
		(width 0.088646)
		(layer "In6.Cu")
		(net "M_C_CPU1_SB_DQS_DN<5>")
	)
	(segment
		(start 90.211656 -241.970052)
		(end 90.199718 -241.96294)
		(width 0.088646)
		(layer "In6.Cu")
		(net "M_C_CPU1_SB_DQS_DN<5>")
	)
	(segment
		(start 57.666382 -233.32694)
		(end 57.117742 -233.32694)
		(width 0.18288)
		(layer "In6.Cu")
		(net "M_C_CPU1_SB_DQS_DN<5>")
	)
	(segment
		(start 38.983412 -228.97846)
		(end 37.822378 -227.817426)
		(width 0.18288)
		(layer "In6.Cu")
		(net "M_C_CPU1_SB_DQS_DN<5>")
	)
	(segment
		(start 47.524416 -231.462072)
		(end 47.244762 -231.741726)
		(width 0.18288)
		(layer "In6.Cu")
		(net "M_C_CPU1_SB_DQS_DN<5>")
	)
	(segment
		(start 86.45271 -241.970052)
		(end 86.440772 -241.96294)
		(width 0.088646)
		(layer "In6.Cu")
		(net "M_C_CPU1_SB_DQS_DN<5>")
	)
	(segment
		(start 45.82541 -231.45623)
		(end 45.059346 -230.690166)
		(width 0.18288)
		(layer "In6.Cu")
		(net "M_C_CPU1_SB_DQS_DN<5>")
	)
	(segment
		(start 43.814746 -230.009446)
		(end 41.067482 -230.009446)
		(width 0.18288)
		(layer "In6.Cu")
		(net "M_C_CPU1_SB_DQS_DN<5>")
	)
	(segment
		(start 49.93513 -232.306114)
		(end 49.349406 -231.72039)
		(width 0.18288)
		(layer "In6.Cu")
		(net "M_C_CPU1_SB_DQS_DN<5>")
	)
	(segment
		(start 46.766226 -231.741726)
		(end 46.48073 -231.45623)
		(width 0.18288)
		(layer "In6.Cu")
		(net "M_C_CPU1_SB_DQS_DN<5>")
	)
	(segment
		(start 50.580798 -232.306114)
		(end 49.93513 -232.306114)
		(width 0.18288)
		(layer "In6.Cu")
		(net "M_C_CPU1_SB_DQS_DN<5>")
	)
	(segment
		(start 88.342724 -241.976148)
		(end 88.320626 -241.963194)
		(width 0.088646)
		(layer "In6.Cu")
		(net "M_C_CPU1_SB_DQS_DN<5>")
	)
	(segment
		(start 84.482178 -241.740944)
		(end 84.361782 -241.620548)
		(width 0.088646)
		(layer "In6.Cu")
		(net "M_C_CPU1_SB_DQS_DN<5>")
	)
	(segment
		(start 92.091256 -241.970052)
		(end 92.079318 -241.96294)
		(width 0.088646)
		(layer "In6.Cu")
		(net "M_C_CPU1_SB_DQS_DN<5>")
	)
	(segment
		(start 87.03056 -241.96294)
		(end 87.018622 -241.970052)
		(width 0.088646)
		(layer "In6.Cu")
		(net "M_C_CPU1_SB_DQS_DN<5>")
	)
	(segment
		(start 71.661782 -240.618264)
		(end 67.375024 -236.331506)
		(width 0.18288)
		(layer "In6.Cu")
		(net "M_C_CPU1_SB_DQS_DN<5>")
	)
	(segment
		(start 96.916494 -242.294918)
		(end 96.973644 -242.237768)
		(width 0.088646)
		(layer "In6.Cu")
		(net "M_C_CPU1_SB_DQS_DN<5>")
	)
	(segment
		(start 59.509152 -233.948224)
		(end 58.763408 -233.20248)
		(width 0.18288)
		(layer "In6.Cu")
		(net "M_C_CPU1_SB_DQS_DN<5>")
	)
	(segment
		(start 50.866548 -232.591864)
		(end 50.580798 -232.306114)
		(width 0.18288)
		(layer "In6.Cu")
		(net "M_C_CPU1_SB_DQS_DN<5>")
	)
	(segment
		(start 51.602132 -232.334308)
		(end 51.344576 -232.591864)
		(width 0.18288)
		(layer "In6.Cu")
		(net "M_C_CPU1_SB_DQS_DN<5>")
	)
	(segment
		(start 57.117742 -233.32694)
		(end 56.993282 -233.20248)
		(width 0.18288)
		(layer "In6.Cu")
		(net "M_C_CPU1_SB_DQS_DN<5>")
	)
	(segment
		(start 45.059346 -230.690166)
		(end 44.495466 -230.690166)
		(width 0.18288)
		(layer "In6.Cu")
		(net "M_C_CPU1_SB_DQS_DN<5>")
	)
	(segment
		(start 36.595304 -227.657914)
		(end 36.23564 -227.657914)
		(width 0.18288)
		(layer "In6.Cu")
		(net "M_C_CPU1_SB_DQS_DN<5>")
	)
	(segment
		(start 96.796352 -241.973608)
		(end 96.790764 -241.97056)
		(width 0.088646)
		(layer "In6.Cu")
		(net "M_C_CPU1_SB_DQS_DN<5>")
	)
	(segment
		(start 94.910656 -241.970052)
		(end 94.902274 -241.965226)
		(width 0.088646)
		(layer "In6.Cu")
		(net "M_C_CPU1_SB_DQS_DN<5>")
	)
	(segment
		(start 61.246766 -233.948224)
		(end 61.122306 -234.072684)
		(width 0.18288)
		(layer "In6.Cu")
		(net "M_C_CPU1_SB_DQS_DN<5>")
	)
	(segment
		(start 48.028352 -231.462072)
		(end 47.524416 -231.462072)
		(width 0.18288)
		(layer "In6.Cu")
		(net "M_C_CPU1_SB_DQS_DN<5>")
	)
	(segment
		(start 61.122306 -234.072684)
		(end 60.573666 -234.072684)
		(width 0.18288)
		(layer "In6.Cu")
		(net "M_C_CPU1_SB_DQS_DN<5>")
	)
	(segment
		(start 40.036496 -228.97846)
		(end 38.983412 -228.97846)
		(width 0.18288)
		(layer "In6.Cu")
		(net "M_C_CPU1_SB_DQS_DN<5>")
	)
	(segment
		(start 96.416114 -241.97056)
		(end 96.41586 -241.970306)
		(width 0.088646)
		(layer "In6.Cu")
		(net "M_C_CPU1_SB_DQS_DN<5>")
	)
	(segment
		(start 93.97111 -241.970052)
		(end 93.962728 -241.965226)
		(width 0.088646)
		(layer "In6.Cu")
		(net "M_C_CPU1_SB_DQS_DN<5>")
	)
	(segment
		(start 83.112864 -240.618264)
		(end 83.089496 -240.618264)
		(width 0.088646)
		(layer "In6.Cu")
		(net "M_C_CPU1_SB_DQS_DN<5>")
	)
	(segment
		(start 36.23564 -227.657914)
		(end 35.976814 -227.91674)
		(width 0.18288)
		(layer "In6.Cu")
		(net "M_C_CPU1_SB_DQS_DN<5>")
	)
	(segment
		(start 36.754816 -227.817426)
		(end 36.595304 -227.657914)
		(width 0.18288)
		(layer "In6.Cu")
		(net "M_C_CPU1_SB_DQS_DN<5>")
	)
	(segment
		(start 85.530436 -241.98072)
		(end 85.49386 -241.959384)
		(width 0.088646)
		(layer "In6.Cu")
		(net "M_C_CPU1_SB_DQS_DN<5>")
	)
	(segment
		(start 55.00243 -232.334308)
		(end 51.602132 -232.334308)
		(width 0.18288)
		(layer "In6.Cu")
		(net "M_C_CPU1_SB_DQS_DN<5>")
	)
	(arc
		(start 87.018622 -241.970052)
		(mid 86.735666 -242.046023)
		(end 86.45271 -241.970052)
		(width 0.088646)
		(layer "In6.Cu")
		(net "M_C_CPU1_SB_DQS_DN<5>")
	)
	(arc
		(start 90.77706 -241.970306)
		(mid 90.494329 -242.045989)
		(end 90.211656 -241.970052)
		(width 0.088646)
		(layer "In6.Cu")
		(net "M_C_CPU1_SB_DQS_DN<5>")
	)
	(arc
		(start 95.838518 -241.96294)
		(mid 95.656348 -241.919951)
		(end 95.47606 -241.970306)
		(width 0.088646)
		(layer "In6.Cu")
		(net "M_C_CPU1_SB_DQS_DN<5>")
	)
	(arc
		(start 93.962728 -241.965226)
		(mid 93.778936 -241.920013)
		(end 93.59646 -241.970306)
		(width 0.088646)
		(layer "In6.Cu")
		(net "M_C_CPU1_SB_DQS_DN<5>")
	)
	(arc
		(start 92.65666 -241.970306)
		(mid 92.373929 -242.045989)
		(end 92.091256 -241.970052)
		(width 0.088646)
		(layer "In6.Cu")
		(net "M_C_CPU1_SB_DQS_DN<5>")
	)
	(arc
		(start 96.973898 -242.237768)
		(mid 96.914568 -242.085898)
		(end 96.796352 -241.973608)
		(width 0.088646)
		(layer "In6.Cu")
		(net "M_C_CPU1_SB_DQS_DN<5>")
	)
	(arc
		(start 88.89746 -241.970306)
		(mid 88.620871 -242.045959)
		(end 88.342724 -241.976148)
		(width 0.088646)
		(layer "In6.Cu")
		(net "M_C_CPU1_SB_DQS_DN<5>")
	)
	(arc
		(start 93.019118 -241.96294)
		(mid 92.836948 -241.919951)
		(end 92.65666 -241.970306)
		(width 0.088646)
		(layer "In6.Cu")
		(net "M_C_CPU1_SB_DQS_DN<5>")
	)
	(arc
		(start 88.320626 -241.963194)
		(mid 88.138341 -241.919931)
		(end 87.957914 -241.970306)
		(width 0.088646)
		(layer "In6.Cu")
		(net "M_C_CPU1_SB_DQS_DN<5>")
	)
	(arc
		(start 85.223096 -241.93373)
		(mid 84.826445 -241.938039)
		(end 84.482178 -241.740944)
		(width 0.088646)
		(layer "In6.Cu")
		(net "M_C_CPU1_SB_DQS_DN<5>")
	)
	(arc
		(start 89.83726 -241.970306)
		(mid 89.554529 -242.045989)
		(end 89.271856 -241.970052)
		(width 0.088646)
		(layer "In6.Cu")
		(net "M_C_CPU1_SB_DQS_DN<5>")
	)
	(arc
		(start 84.361782 -241.620548)
		(mid 84.277734 -241.518344)
		(end 84.21497 -241.401854)
		(width 0.088646)
		(layer "In6.Cu")
		(net "M_C_CPU1_SB_DQS_DN<5>")
	)
	(arc
		(start 89.259918 -241.96294)
		(mid 89.077748 -241.919951)
		(end 88.89746 -241.970306)
		(width 0.088646)
		(layer "In6.Cu")
		(net "M_C_CPU1_SB_DQS_DN<5>")
	)
	(arc
		(start 86.077806 -241.970306)
		(mid 85.805452 -242.046266)
		(end 85.530436 -241.98072)
		(width 0.088646)
		(layer "In6.Cu")
		(net "M_C_CPU1_SB_DQS_DN<5>")
	)
	(arc
		(start 84.21497 -241.401854)
		(mid 84.186941 -241.350024)
		(end 84.149438 -241.304572)
		(width 0.088646)
		(layer "In6.Cu")
		(net "M_C_CPU1_SB_DQS_DN<5>")
	)
	(arc
		(start 95.47606 -241.970306)
		(mid 95.193329 -242.045989)
		(end 94.910656 -241.970052)
		(width 0.088646)
		(layer "In6.Cu")
		(net "M_C_CPU1_SB_DQS_DN<5>")
	)
	(arc
		(start 93.59646 -241.970306)
		(mid 93.313729 -242.045989)
		(end 93.031056 -241.970052)
		(width 0.088646)
		(layer "In6.Cu")
		(net "M_C_CPU1_SB_DQS_DN<5>")
	)
	(arc
		(start 91.139518 -241.96294)
		(mid 90.957348 -241.919951)
		(end 90.77706 -241.970306)
		(width 0.088646)
		(layer "In6.Cu")
		(net "M_C_CPU1_SB_DQS_DN<5>")
	)
	(arc
		(start 90.199718 -241.96294)
		(mid 90.017548 -241.919951)
		(end 89.83726 -241.970306)
		(width 0.088646)
		(layer "In6.Cu")
		(net "M_C_CPU1_SB_DQS_DN<5>")
	)
	(arc
		(start 87.393018 -241.970306)
		(mid 87.212731 -241.919894)
		(end 87.03056 -241.96294)
		(width 0.088646)
		(layer "In6.Cu")
		(net "M_C_CPU1_SB_DQS_DN<5>")
	)
	(arc
		(start 85.49386 -241.959384)
		(mid 85.360882 -241.92117)
		(end 85.223096 -241.93373)
		(width 0.088646)
		(layer "In6.Cu")
		(net "M_C_CPU1_SB_DQS_DN<5>")
	)
	(arc
		(start 91.71686 -241.970306)
		(mid 91.434129 -242.045989)
		(end 91.151456 -241.970052)
		(width 0.088646)
		(layer "In6.Cu")
		(net "M_C_CPU1_SB_DQS_DN<5>")
	)
	(arc
		(start 94.902274 -241.965226)
		(mid 94.718736 -241.920134)
		(end 94.536514 -241.970306)
		(width 0.088646)
		(layer "In6.Cu")
		(net "M_C_CPU1_SB_DQS_DN<5>")
	)
	(arc
		(start 92.079318 -241.96294)
		(mid 91.897148 -241.919951)
		(end 91.71686 -241.970306)
		(width 0.088646)
		(layer "In6.Cu")
		(net "M_C_CPU1_SB_DQS_DN<5>")
	)
	(arc
		(start 94.536514 -241.970306)
		(mid 94.253783 -242.045989)
		(end 93.97111 -241.970052)
		(width 0.088646)
		(layer "In6.Cu")
		(net "M_C_CPU1_SB_DQS_DN<5>")
	)
	(arc
		(start 96.41586 -241.970306)
		(mid 96.133129 -242.045989)
		(end 95.850456 -241.970052)
		(width 0.088646)
		(layer "In6.Cu")
		(net "M_C_CPU1_SB_DQS_DN<5>")
	)
	(arc
		(start 96.790764 -241.97056)
		(mid 96.603566 -241.920417)
		(end 96.416368 -241.97056)
		(width 0.088646)
		(layer "In6.Cu")
		(net "M_C_CPU1_SB_DQS_DN<5>")
	)
	(arc
		(start 86.440772 -241.96294)
		(mid 86.258348 -241.919833)
		(end 86.077806 -241.970306)
		(width 0.088646)
		(layer "In6.Cu")
		(net "M_C_CPU1_SB_DQS_DN<5>")
	)
	(arc
		(start 87.957914 -241.970306)
		(mid 87.675466 -242.045989)
		(end 87.393018 -241.970306)
		(width 0.088646)
		(layer "In6.Cu")
		(net "M_C_CPU1_SB_DQS_DN<5>")
	)
	(segment
		(start 32.37611 -236.58068)
		(end 32.780732 -236.58068)
		(width 0.20066)
		(layer "F.Cu")
		(net "M_C_CPU1_SB_DQS_DN<4>")
	)
	(segment
		(start 29.454856 -236.841792)
		(end 29.50464 -236.841792)
		(width 0.20066)
		(layer "F.Cu")
		(net "M_C_CPU1_SB_DQS_DN<4>")
	)
	(segment
		(start 29.196284 -236.58322)
		(end 29.454856 -236.841792)
		(width 0.20066)
		(layer "F.Cu")
		(net "M_C_CPU1_SB_DQS_DN<4>")
	)
	(segment
		(start 28.956508 -236.58322)
		(end 29.196284 -236.58322)
		(width 0.20066)
		(layer "F.Cu")
		(net "M_C_CPU1_SB_DQS_DN<4>")
	)
	(segment
		(start 28.534106 -237.005622)
		(end 28.956508 -236.58322)
		(width 0.20066)
		(layer "F.Cu")
		(net "M_C_CPU1_SB_DQS_DN<4>")
	)
	(segment
		(start 34.38144 -237.266734)
		(end 34.871914 -237.266734)
		(width 0.20066)
		(layer "F.Cu")
		(net "M_C_CPU1_SB_DQS_DN<4>")
	)
	(segment
		(start 93.314266 -240.389156)
		(end 93.314266 -239.85347)
		(width 0.20066)
		(layer "F.Cu")
		(net "M_C_CPU1_SB_DQS_DN<4>")
	)
	(segment
		(start 33.416748 -237.005622)
		(end 34.120328 -237.005622)
		(width 0.20066)
		(layer "F.Cu")
		(net "M_C_CPU1_SB_DQS_DN<4>")
	)
	(segment
		(start 27.799792 -237.266734)
		(end 28.060904 -237.005622)
		(width 0.20066)
		(layer "F.Cu")
		(net "M_C_CPU1_SB_DQS_DN<4>")
	)
	(segment
		(start 32.114998 -236.841792)
		(end 32.37611 -236.58068)
		(width 0.20066)
		(layer "F.Cu")
		(net "M_C_CPU1_SB_DQS_DN<4>")
	)
	(segment
		(start 29.50464 -236.841792)
		(end 29.895292 -236.841792)
		(width 0.101854)
		(layer "F.Cu")
		(net "M_C_CPU1_SB_DQS_DN<4>")
	)
	(segment
		(start 29.895292 -236.841792)
		(end 31.972758 -236.841792)
		(width 0.1016)
		(layer "F.Cu")
		(net "M_C_CPU1_SB_DQS_DN<4>")
	)
	(segment
		(start 35.976814 -237.266734)
		(end 34.871914 -237.266734)
		(width 0.20066)
		(layer "F.Cu")
		(net "M_C_CPU1_SB_DQS_DN<4>")
	)
	(segment
		(start 32.780732 -236.58068)
		(end 33.416748 -237.005622)
		(width 0.20066)
		(layer "F.Cu")
		(net "M_C_CPU1_SB_DQS_DN<4>")
	)
	(segment
		(start 27.328114 -237.266734)
		(end 27.799792 -237.266734)
		(width 0.20066)
		(layer "F.Cu")
		(net "M_C_CPU1_SB_DQS_DN<4>")
	)
	(segment
		(start 31.972758 -236.841792)
		(end 32.025336 -236.841792)
		(width 0.101854)
		(layer "F.Cu")
		(net "M_C_CPU1_SB_DQS_DN<4>")
	)
	(segment
		(start 32.025336 -236.841792)
		(end 32.114998 -236.841792)
		(width 0.20066)
		(layer "F.Cu")
		(net "M_C_CPU1_SB_DQS_DN<4>")
	)
	(segment
		(start 93.314266 -239.85347)
		(end 93.314012 -239.853216)
		(width 0.20066)
		(layer "F.Cu")
		(net "M_C_CPU1_SB_DQS_DN<4>")
	)
	(segment
		(start 34.120328 -237.005622)
		(end 34.38144 -237.266734)
		(width 0.20066)
		(layer "F.Cu")
		(net "M_C_CPU1_SB_DQS_DN<4>")
	)
	(segment
		(start 28.060904 -237.005622)
		(end 28.534106 -237.005622)
		(width 0.20066)
		(layer "F.Cu")
		(net "M_C_CPU1_SB_DQS_DN<4>")
	)
	(segment
		(start 46.503844 -236.574584)
		(end 45.672502 -236.574584)
		(width 0.18288)
		(layer "In4.Cu")
		(net "M_C_CPU1_SB_DQS_DN<4>")
	)
	(segment
		(start 41.280842 -236.397292)
		(end 40.62476 -236.397292)
		(width 0.18288)
		(layer "In4.Cu")
		(net "M_C_CPU1_SB_DQS_DN<4>")
	)
	(segment
		(start 67.72529 -237.447582)
		(end 67.17665 -237.447582)
		(width 0.18288)
		(layer "In4.Cu")
		(net "M_C_CPU1_SB_DQS_DN<4>")
	)
	(segment
		(start 68.419726 -238.31804)
		(end 68.419726 -238.142018)
		(width 0.18288)
		(layer "In4.Cu")
		(net "M_C_CPU1_SB_DQS_DN<4>")
	)
	(segment
		(start 86.54669 -239.52962)
		(end 86.539324 -239.533938)
		(width 0.088646)
		(layer "In4.Cu")
		(net "M_C_CPU1_SB_DQS_DN<4>")
	)
	(segment
		(start 39.140638 -237.332774)
		(end 38.591998 -237.332774)
		(width 0.18288)
		(layer "In4.Cu")
		(net "M_C_CPU1_SB_DQS_DN<4>")
	)
	(segment
		(start 84.213954 -240.418874)
		(end 83.914742 -240.718086)
		(width 0.088646)
		(layer "In4.Cu")
		(net "M_C_CPU1_SB_DQS_DN<4>")
	)
	(segment
		(start 88.427814 -239.528858)
		(end 88.413082 -239.537494)
		(width 0.088646)
		(layer "In4.Cu")
		(net "M_C_CPU1_SB_DQS_DN<4>")
	)
	(segment
		(start 85.527896 -240.351564)
		(end 85.513164 -240.342928)
		(width 0.088646)
		(layer "In4.Cu")
		(net "M_C_CPU1_SB_DQS_DN<4>")
	)
	(segment
		(start 91.247214 -239.528858)
		(end 91.2368 -239.534954)
		(width 0.088646)
		(layer "In4.Cu")
		(net "M_C_CPU1_SB_DQS_DN<4>")
	)
	(segment
		(start 41.405302 -236.521752)
		(end 41.280842 -236.397292)
		(width 0.18288)
		(layer "In4.Cu")
		(net "M_C_CPU1_SB_DQS_DN<4>")
	)
	(segment
		(start 59.009534 -236.540294)
		(end 55.739284 -236.540294)
		(width 0.18288)
		(layer "In4.Cu")
		(net "M_C_CPU1_SB_DQS_DN<4>")
	)
	(segment
		(start 68.984114 -238.706406)
		(end 68.808092 -238.706406)
		(width 0.18288)
		(layer "In4.Cu")
		(net "M_C_CPU1_SB_DQS_DN<4>")
	)
	(segment
		(start 68.419726 -238.142018)
		(end 67.72529 -237.447582)
		(width 0.18288)
		(layer "In4.Cu")
		(net "M_C_CPU1_SB_DQS_DN<4>")
	)
	(segment
		(start 55.739284 -236.540294)
		(end 55.112412 -237.167166)
		(width 0.18288)
		(layer "In4.Cu")
		(net "M_C_CPU1_SB_DQS_DN<4>")
	)
	(segment
		(start 93.314012 -239.853216)
		(end 92.963492 -239.644428)
		(width 0.088646)
		(layer "In4.Cu")
		(net "M_C_CPU1_SB_DQS_DN<4>")
	)
	(segment
		(start 38.591998 -237.332774)
		(end 38.467538 -237.208314)
		(width 0.18288)
		(layer "In4.Cu")
		(net "M_C_CPU1_SB_DQS_DN<4>")
	)
	(segment
		(start 45.672502 -236.574584)
		(end 45.055536 -235.957618)
		(width 0.18288)
		(layer "In4.Cu")
		(net "M_C_CPU1_SB_DQS_DN<4>")
	)
	(segment
		(start 38.467538 -237.208314)
		(end 36.848288 -237.208314)
		(width 0.18288)
		(layer "In4.Cu")
		(net "M_C_CPU1_SB_DQS_DN<4>")
	)
	(segment
		(start 47.142908 -236.841792)
		(end 46.771052 -236.841792)
		(width 0.18288)
		(layer "In4.Cu")
		(net "M_C_CPU1_SB_DQS_DN<4>")
	)
	(segment
		(start 65.83045 -237.447582)
		(end 65.70599 -237.572042)
		(width 0.18288)
		(layer "In4.Cu")
		(net "M_C_CPU1_SB_DQS_DN<4>")
	)
	(segment
		(start 51.245008 -235.991908)
		(end 50.869088 -235.991908)
		(width 0.18288)
		(layer "In4.Cu")
		(net "M_C_CPU1_SB_DQS_DN<4>")
	)
	(segment
		(start 83.105752 -240.77803)
		(end 83.064096 -240.77803)
		(width 0.088646)
		(layer "In4.Cu")
		(net "M_C_CPU1_SB_DQS_DN<4>")
	)
	(segment
		(start 39.813738 -237.208314)
		(end 39.265098 -237.208314)
		(width 0.18288)
		(layer "In4.Cu")
		(net "M_C_CPU1_SB_DQS_DN<4>")
	)
	(segment
		(start 42.627042 -236.397292)
		(end 42.078402 -236.397292)
		(width 0.18288)
		(layer "In4.Cu")
		(net "M_C_CPU1_SB_DQS_DN<4>")
	)
	(segment
		(start 67.05219 -237.572042)
		(end 66.50355 -237.572042)
		(width 0.18288)
		(layer "In4.Cu")
		(net "M_C_CPU1_SB_DQS_DN<4>")
	)
	(segment
		(start 59.55538 -235.994448)
		(end 59.009534 -236.540294)
		(width 0.18288)
		(layer "In4.Cu")
		(net "M_C_CPU1_SB_DQS_DN<4>")
	)
	(segment
		(start 63.81115 -237.572042)
		(end 63.68669 -237.447582)
		(width 0.18288)
		(layer "In4.Cu")
		(net "M_C_CPU1_SB_DQS_DN<4>")
	)
	(segment
		(start 53.72735 -236.779308)
		(end 53.551328 -236.779308)
		(width 0.18288)
		(layer "In4.Cu")
		(net "M_C_CPU1_SB_DQS_DN<4>")
	)
	(segment
		(start 61.53277 -237.038134)
		(end 61.144404 -236.649768)
		(width 0.18288)
		(layer "In4.Cu")
		(net "M_C_CPU1_SB_DQS_DN<4>")
	)
	(segment
		(start 51.510946 -235.72597)
		(end 51.245008 -235.991908)
		(width 0.18288)
		(layer "In4.Cu")
		(net "M_C_CPU1_SB_DQS_DN<4>")
	)
	(segment
		(start 61.708792 -237.038134)
		(end 61.53277 -237.038134)
		(width 0.18288)
		(layer "In4.Cu")
		(net "M_C_CPU1_SB_DQS_DN<4>")
	)
	(segment
		(start 41.953942 -236.521752)
		(end 41.405302 -236.521752)
		(width 0.18288)
		(layer "In4.Cu")
		(net "M_C_CPU1_SB_DQS_DN<4>")
	)
	(segment
		(start 66.50355 -237.572042)
		(end 66.37909 -237.447582)
		(width 0.18288)
		(layer "In4.Cu")
		(net "M_C_CPU1_SB_DQS_DN<4>")
	)
	(segment
		(start 83.914742 -240.718086)
		(end 83.165696 -240.718086)
		(width 0.088646)
		(layer "In4.Cu")
		(net "M_C_CPU1_SB_DQS_DN<4>")
	)
	(segment
		(start 64.48425 -237.447582)
		(end 64.35979 -237.572042)
		(width 0.18288)
		(layer "In4.Cu")
		(net "M_C_CPU1_SB_DQS_DN<4>")
	)
	(segment
		(start 47.418244 -236.566456)
		(end 47.142908 -236.841792)
		(width 0.18288)
		(layer "In4.Cu")
		(net "M_C_CPU1_SB_DQS_DN<4>")
	)
	(segment
		(start 36.24834 -236.995208)
		(end 35.976814 -237.266734)
		(width 0.18288)
		(layer "In4.Cu")
		(net "M_C_CPU1_SB_DQS_DN<4>")
	)
	(segment
		(start 65.03289 -237.447582)
		(end 64.48425 -237.447582)
		(width 0.18288)
		(layer "In4.Cu")
		(net "M_C_CPU1_SB_DQS_DN<4>")
	)
	(segment
		(start 44.412916 -235.957618)
		(end 43.973242 -236.397292)
		(width 0.18288)
		(layer "In4.Cu")
		(net "M_C_CPU1_SB_DQS_DN<4>")
	)
	(segment
		(start 42.751502 -236.521752)
		(end 42.627042 -236.397292)
		(width 0.18288)
		(layer "In4.Cu")
		(net "M_C_CPU1_SB_DQS_DN<4>")
	)
	(segment
		(start 50.869088 -235.991908)
		(end 50.593752 -235.716572)
		(width 0.18288)
		(layer "In4.Cu")
		(net "M_C_CPU1_SB_DQS_DN<4>")
	)
	(segment
		(start 42.078402 -236.397292)
		(end 41.953942 -236.521752)
		(width 0.18288)
		(layer "In4.Cu")
		(net "M_C_CPU1_SB_DQS_DN<4>")
	)
	(segment
		(start 61.144404 -236.473746)
		(end 60.665106 -235.994448)
		(width 0.18288)
		(layer "In4.Cu")
		(net "M_C_CPU1_SB_DQS_DN<4>")
	)
	(segment
		(start 90.307668 -239.528858)
		(end 90.297254 -239.534954)
		(width 0.088646)
		(layer "In4.Cu")
		(net "M_C_CPU1_SB_DQS_DN<4>")
	)
	(segment
		(start 86.548214 -239.528858)
		(end 86.54669 -239.52962)
		(width 0.088646)
		(layer "In4.Cu")
		(net "M_C_CPU1_SB_DQS_DN<4>")
	)
	(segment
		(start 52.674012 -235.72597)
		(end 51.510946 -235.72597)
		(width 0.18288)
		(layer "In4.Cu")
		(net "M_C_CPU1_SB_DQS_DN<4>")
	)
	(segment
		(start 92.187014 -239.528858)
		(end 92.172282 -239.537494)
		(width 0.088646)
		(layer "In4.Cu")
		(net "M_C_CPU1_SB_DQS_DN<4>")
	)
	(segment
		(start 53.163216 -236.391196)
		(end 53.163216 -236.215174)
		(width 0.18288)
		(layer "In4.Cu")
		(net "M_C_CPU1_SB_DQS_DN<4>")
	)
	(segment
		(start 60.665106 -235.994448)
		(end 59.55538 -235.994448)
		(width 0.18288)
		(layer "In4.Cu")
		(net "M_C_CPU1_SB_DQS_DN<4>")
	)
	(segment
		(start 43.424602 -236.397292)
		(end 43.300142 -236.521752)
		(width 0.18288)
		(layer "In4.Cu")
		(net "M_C_CPU1_SB_DQS_DN<4>")
	)
	(segment
		(start 46.771052 -236.841792)
		(end 46.503844 -236.574584)
		(width 0.18288)
		(layer "In4.Cu")
		(net "M_C_CPU1_SB_DQS_DN<4>")
	)
	(segment
		(start 50.268378 -235.716572)
		(end 49.418494 -236.566456)
		(width 0.18288)
		(layer "In4.Cu")
		(net "M_C_CPU1_SB_DQS_DN<4>")
	)
	(segment
		(start 65.70599 -237.572042)
		(end 65.15735 -237.572042)
		(width 0.18288)
		(layer "In4.Cu")
		(net "M_C_CPU1_SB_DQS_DN<4>")
	)
	(segment
		(start 89.367614 -239.528858)
		(end 89.352882 -239.537494)
		(width 0.088646)
		(layer "In4.Cu")
		(net "M_C_CPU1_SB_DQS_DN<4>")
	)
	(segment
		(start 43.973242 -236.397292)
		(end 43.424602 -236.397292)
		(width 0.18288)
		(layer "In4.Cu")
		(net "M_C_CPU1_SB_DQS_DN<4>")
	)
	(segment
		(start 49.418494 -236.566456)
		(end 47.418244 -236.566456)
		(width 0.18288)
		(layer "In4.Cu")
		(net "M_C_CPU1_SB_DQS_DN<4>")
	)
	(segment
		(start 54.115208 -237.167166)
		(end 53.72735 -236.779308)
		(width 0.18288)
		(layer "In4.Cu")
		(net "M_C_CPU1_SB_DQS_DN<4>")
	)
	(segment
		(start 45.055536 -235.957618)
		(end 44.412916 -235.957618)
		(width 0.18288)
		(layer "In4.Cu")
		(net "M_C_CPU1_SB_DQS_DN<4>")
	)
	(segment
		(start 40.62476 -236.397292)
		(end 39.813738 -237.208314)
		(width 0.18288)
		(layer "In4.Cu")
		(net "M_C_CPU1_SB_DQS_DN<4>")
	)
	(segment
		(start 68.808092 -238.706406)
		(end 68.419726 -238.31804)
		(width 0.18288)
		(layer "In4.Cu")
		(net "M_C_CPU1_SB_DQS_DN<4>")
	)
	(segment
		(start 53.163216 -236.215174)
		(end 52.674012 -235.72597)
		(width 0.18288)
		(layer "In4.Cu")
		(net "M_C_CPU1_SB_DQS_DN<4>")
	)
	(segment
		(start 50.593752 -235.716572)
		(end 50.268378 -235.716572)
		(width 0.18288)
		(layer "In4.Cu")
		(net "M_C_CPU1_SB_DQS_DN<4>")
	)
	(segment
		(start 65.15735 -237.572042)
		(end 65.03289 -237.447582)
		(width 0.18288)
		(layer "In4.Cu")
		(net "M_C_CPU1_SB_DQS_DN<4>")
	)
	(segment
		(start 36.635182 -236.995208)
		(end 36.24834 -236.995208)
		(width 0.18288)
		(layer "In4.Cu")
		(net "M_C_CPU1_SB_DQS_DN<4>")
	)
	(segment
		(start 36.848288 -237.208314)
		(end 36.635182 -236.995208)
		(width 0.18288)
		(layer "In4.Cu")
		(net "M_C_CPU1_SB_DQS_DN<4>")
	)
	(segment
		(start 86.360762 -239.853216)
		(end 86.360762 -239.875314)
		(width 0.088646)
		(layer "In4.Cu")
		(net "M_C_CPU1_SB_DQS_DN<4>")
	)
	(segment
		(start 43.300142 -236.521752)
		(end 42.751502 -236.521752)
		(width 0.18288)
		(layer "In4.Cu")
		(net "M_C_CPU1_SB_DQS_DN<4>")
	)
	(segment
		(start 39.265098 -237.208314)
		(end 39.140638 -237.332774)
		(width 0.18288)
		(layer "In4.Cu")
		(net "M_C_CPU1_SB_DQS_DN<4>")
	)
	(segment
		(start 71.055738 -240.77803)
		(end 68.984114 -238.706406)
		(width 0.18288)
		(layer "In4.Cu")
		(net "M_C_CPU1_SB_DQS_DN<4>")
	)
	(segment
		(start 84.855812 -240.418874)
		(end 84.213954 -240.418874)
		(width 0.088646)
		(layer "In4.Cu")
		(net "M_C_CPU1_SB_DQS_DN<4>")
	)
	(segment
		(start 87.488014 -239.528858)
		(end 87.473282 -239.537494)
		(width 0.088646)
		(layer "In4.Cu")
		(net "M_C_CPU1_SB_DQS_DN<4>")
	)
	(segment
		(start 61.144404 -236.649768)
		(end 61.144404 -236.473746)
		(width 0.18288)
		(layer "In4.Cu")
		(net "M_C_CPU1_SB_DQS_DN<4>")
	)
	(segment
		(start 66.37909 -237.447582)
		(end 65.83045 -237.447582)
		(width 0.18288)
		(layer "In4.Cu")
		(net "M_C_CPU1_SB_DQS_DN<4>")
	)
	(segment
		(start 83.165696 -240.718086)
		(end 83.105752 -240.77803)
		(width 0.088646)
		(layer "In4.Cu")
		(net "M_C_CPU1_SB_DQS_DN<4>")
	)
	(segment
		(start 67.17665 -237.447582)
		(end 67.05219 -237.572042)
		(width 0.18288)
		(layer "In4.Cu")
		(net "M_C_CPU1_SB_DQS_DN<4>")
	)
	(segment
		(start 62.11824 -237.447582)
		(end 61.708792 -237.038134)
		(width 0.18288)
		(layer "In4.Cu")
		(net "M_C_CPU1_SB_DQS_DN<4>")
	)
	(segment
		(start 83.064096 -240.77803)
		(end 71.055738 -240.77803)
		(width 0.18288)
		(layer "In4.Cu")
		(net "M_C_CPU1_SB_DQS_DN<4>")
	)
	(segment
		(start 55.112412 -237.167166)
		(end 54.115208 -237.167166)
		(width 0.18288)
		(layer "In4.Cu")
		(net "M_C_CPU1_SB_DQS_DN<4>")
	)
	(segment
		(start 63.68669 -237.447582)
		(end 62.11824 -237.447582)
		(width 0.18288)
		(layer "In4.Cu")
		(net "M_C_CPU1_SB_DQS_DN<4>")
	)
	(segment
		(start 53.551328 -236.779308)
		(end 53.163216 -236.391196)
		(width 0.18288)
		(layer "In4.Cu")
		(net "M_C_CPU1_SB_DQS_DN<4>")
	)
	(segment
		(start 64.35979 -237.572042)
		(end 63.81115 -237.572042)
		(width 0.18288)
		(layer "In4.Cu")
		(net "M_C_CPU1_SB_DQS_DN<4>")
	)
	(arc
		(start 88.80221 -239.528858)
		(mid 88.615012 -239.478715)
		(end 88.427814 -239.528858)
		(width 0.088646)
		(layer "In4.Cu")
		(net "M_C_CPU1_SB_DQS_DN<4>")
	)
	(arc
		(start 92.963492 -239.644428)
		(mid 92.897946 -239.615934)
		(end 92.827348 -239.604804)
		(width 0.088646)
		(layer "In4.Cu")
		(net "M_C_CPU1_SB_DQS_DN<4>")
	)
	(arc
		(start 90.682064 -239.528858)
		(mid 90.494866 -239.478715)
		(end 90.307668 -239.528858)
		(width 0.088646)
		(layer "In4.Cu")
		(net "M_C_CPU1_SB_DQS_DN<4>")
	)
	(arc
		(start 89.352882 -239.537494)
		(mid 89.076407 -239.604814)
		(end 88.80221 -239.528858)
		(width 0.088646)
		(layer "In4.Cu")
		(net "M_C_CPU1_SB_DQS_DN<4>")
	)
	(arc
		(start 87.473282 -239.537494)
		(mid 87.196807 -239.604814)
		(end 86.92261 -239.528858)
		(width 0.088646)
		(layer "In4.Cu")
		(net "M_C_CPU1_SB_DQS_DN<4>")
	)
	(arc
		(start 86.92261 -239.528858)
		(mid 86.735412 -239.478715)
		(end 86.548214 -239.528858)
		(width 0.088646)
		(layer "In4.Cu")
		(net "M_C_CPU1_SB_DQS_DN<4>")
	)
	(arc
		(start 91.62161 -239.528858)
		(mid 91.434412 -239.478715)
		(end 91.247214 -239.528858)
		(width 0.088646)
		(layer "In4.Cu")
		(net "M_C_CPU1_SB_DQS_DN<4>")
	)
	(arc
		(start 91.2368 -239.534954)
		(mid 90.958622 -239.604677)
		(end 90.682064 -239.528858)
		(width 0.088646)
		(layer "In4.Cu")
		(net "M_C_CPU1_SB_DQS_DN<4>")
	)
	(arc
		(start 90.297254 -239.534954)
		(mid 90.018822 -239.6048)
		(end 89.74201 -239.528858)
		(width 0.088646)
		(layer "In4.Cu")
		(net "M_C_CPU1_SB_DQS_DN<4>")
	)
	(arc
		(start 89.74201 -239.528858)
		(mid 89.554812 -239.478715)
		(end 89.367614 -239.528858)
		(width 0.088646)
		(layer "In4.Cu")
		(net "M_C_CPU1_SB_DQS_DN<4>")
	)
	(arc
		(start 85.138768 -240.342928)
		(mid 85.002295 -240.399562)
		(end 84.855812 -240.418874)
		(width 0.088646)
		(layer "In4.Cu")
		(net "M_C_CPU1_SB_DQS_DN<4>")
	)
	(arc
		(start 86.360762 -239.875314)
		(mid 86.076331 -240.344215)
		(end 85.527896 -240.351564)
		(width 0.088646)
		(layer "In4.Cu")
		(net "M_C_CPU1_SB_DQS_DN<4>")
	)
	(arc
		(start 85.513164 -240.342928)
		(mid 85.325966 -240.292785)
		(end 85.138768 -240.342928)
		(width 0.088646)
		(layer "In4.Cu")
		(net "M_C_CPU1_SB_DQS_DN<4>")
	)
	(arc
		(start 86.539324 -239.533938)
		(mid 86.40841 -239.670298)
		(end 86.360762 -239.853216)
		(width 0.088646)
		(layer "In4.Cu")
		(net "M_C_CPU1_SB_DQS_DN<4>")
	)
	(arc
		(start 88.413082 -239.537494)
		(mid 88.136607 -239.604814)
		(end 87.86241 -239.528858)
		(width 0.088646)
		(layer "In4.Cu")
		(net "M_C_CPU1_SB_DQS_DN<4>")
	)
	(arc
		(start 92.172282 -239.537494)
		(mid 91.895807 -239.604814)
		(end 91.62161 -239.528858)
		(width 0.088646)
		(layer "In4.Cu")
		(net "M_C_CPU1_SB_DQS_DN<4>")
	)
	(arc
		(start 87.86241 -239.528858)
		(mid 87.675212 -239.478715)
		(end 87.488014 -239.528858)
		(width 0.088646)
		(layer "In4.Cu")
		(net "M_C_CPU1_SB_DQS_DN<4>")
	)
	(arc
		(start 92.56141 -239.528858)
		(mid 92.374212 -239.478715)
		(end 92.187014 -239.528858)
		(width 0.088646)
		(layer "In4.Cu")
		(net "M_C_CPU1_SB_DQS_DN<4>")
	)
	(arc
		(start 92.827348 -239.604804)
		(mid 92.689659 -239.583354)
		(end 92.56141 -239.528858)
		(width 0.088646)
		(layer "In4.Cu")
		(net "M_C_CPU1_SB_DQS_DN<4>")
	)
	(segment
		(start 25.999694 -200.281032)
		(end 26.20391 -200.281032)
		(width 0.20066)
		(layer "F.Cu")
		(net "M_C_CPU1_SB_DQS_DN<3>")
	)
	(segment
		(start 26.204672 -200.281032)
		(end 26.21534 -200.2917)
		(width 0.101854)
		(layer "F.Cu")
		(net "M_C_CPU1_SB_DQS_DN<3>")
	)
	(segment
		(start 26.21534 -200.2917)
		(end 28.529026 -200.2917)
		(width 0.1016)
		(layer "F.Cu")
		(net "M_C_CPU1_SB_DQS_DN<3>")
	)
	(segment
		(start 29.132276 -200.553066)
		(end 29.557472 -200.12787)
		(width 0.20066)
		(layer "F.Cu")
		(net "M_C_CPU1_SB_DQS_DN<3>")
	)
	(segment
		(start 29.964126 -200.12787)
		(end 30.225238 -199.866758)
		(width 0.20066)
		(layer "F.Cu")
		(net "M_C_CPU1_SB_DQS_DN<3>")
	)
	(segment
		(start 30.225238 -199.866758)
		(end 30.771846 -199.866758)
		(width 0.20066)
		(layer "F.Cu")
		(net "M_C_CPU1_SB_DQS_DN<3>")
	)
	(segment
		(start 29.557472 -200.12787)
		(end 29.964126 -200.12787)
		(width 0.20066)
		(layer "F.Cu")
		(net "M_C_CPU1_SB_DQS_DN<3>")
	)
	(segment
		(start 25.72766 -200.553066)
		(end 25.999694 -200.281032)
		(width 0.20066)
		(layer "F.Cu")
		(net "M_C_CPU1_SB_DQS_DN<3>")
	)
	(segment
		(start 94.723966 -228.180646)
		(end 94.723966 -227.64496)
		(width 0.20066)
		(layer "F.Cu")
		(net "M_C_CPU1_SB_DQS_DN<3>")
	)
	(segment
		(start 28.68422 -200.2917)
		(end 28.945586 -200.553066)
		(width 0.20066)
		(layer "F.Cu")
		(net "M_C_CPU1_SB_DQS_DN<3>")
	)
	(segment
		(start 94.723712 -228.1809)
		(end 94.723966 -228.180646)
		(width 0.20066)
		(layer "F.Cu")
		(net "M_C_CPU1_SB_DQS_DN<3>")
	)
	(segment
		(start 24.55164 -200.12787)
		(end 25.187656 -200.553066)
		(width 0.20066)
		(layer "F.Cu")
		(net "M_C_CPU1_SB_DQS_DN<3>")
	)
	(segment
		(start 31.876746 -199.866758)
		(end 30.771846 -199.866758)
		(width 0.20066)
		(layer "F.Cu")
		(net "M_C_CPU1_SB_DQS_DN<3>")
	)
	(segment
		(start 28.945586 -200.553066)
		(end 29.132276 -200.553066)
		(width 0.20066)
		(layer "F.Cu")
		(net "M_C_CPU1_SB_DQS_DN<3>")
	)
	(segment
		(start 25.187656 -200.553066)
		(end 25.72766 -200.553066)
		(width 0.20066)
		(layer "F.Cu")
		(net "M_C_CPU1_SB_DQS_DN<3>")
	)
	(segment
		(start 26.20391 -200.281032)
		(end 26.204672 -200.281032)
		(width 0.101854)
		(layer "F.Cu")
		(net "M_C_CPU1_SB_DQS_DN<3>")
	)
	(segment
		(start 28.529026 -200.2917)
		(end 28.68422 -200.2917)
		(width 0.20066)
		(layer "F.Cu")
		(net "M_C_CPU1_SB_DQS_DN<3>")
	)
	(segment
		(start 23.776686 -199.866758)
		(end 24.037798 -200.12787)
		(width 0.20066)
		(layer "F.Cu")
		(net "M_C_CPU1_SB_DQS_DN<3>")
	)
	(segment
		(start 24.037798 -200.12787)
		(end 24.55164 -200.12787)
		(width 0.20066)
		(layer "F.Cu")
		(net "M_C_CPU1_SB_DQS_DN<3>")
	)
	(segment
		(start 23.228046 -199.866758)
		(end 23.776686 -199.866758)
		(width 0.20066)
		(layer "F.Cu")
		(net "M_C_CPU1_SB_DQS_DN<3>")
	)
	(segment
		(start 65.51676 -202.66406)
		(end 65.51676 -202.488038)
		(width 0.18288)
		(layer "In6.Cu")
		(net "M_C_CPU1_SB_DQS_DN<3>")
	)
	(segment
		(start 45.391832 -198.386446)
		(end 45.0723 -198.254366)
		(width 0.18288)
		(layer "In6.Cu")
		(net "M_C_CPU1_SB_DQS_DN<3>")
	)
	(segment
		(start 67.610482 -204.342238)
		(end 66.356738 -203.088494)
		(width 0.18288)
		(layer "In6.Cu")
		(net "M_C_CPU1_SB_DQS_DN<3>")
	)
	(segment
		(start 82.479642 -223.110044)
		(end 80.73263 -223.110044)
		(width 0.18288)
		(layer "In6.Cu")
		(net "M_C_CPU1_SB_DQS_DN<3>")
	)
	(segment
		(start 63.89624 -201.434954)
		(end 63.828676 -201.271886)
		(width 0.18288)
		(layer "In6.Cu")
		(net "M_C_CPU1_SB_DQS_DN<3>")
	)
	(segment
		(start 65.128648 -202.099672)
		(end 64.952626 -202.099672)
		(width 0.18288)
		(layer "In6.Cu")
		(net "M_C_CPU1_SB_DQS_DN<3>")
	)
	(segment
		(start 40.900096 -199.149208)
		(end 40.211248 -198.863966)
		(width 0.18288)
		(layer "In6.Cu")
		(net "M_C_CPU1_SB_DQS_DN<3>")
	)
	(segment
		(start 65.51676 -202.488038)
		(end 65.128648 -202.099672)
		(width 0.18288)
		(layer "In6.Cu")
		(net "M_C_CPU1_SB_DQS_DN<3>")
	)
	(segment
		(start 85.033358 -225.533458)
		(end 85.031326 -225.534474)
		(width 0.088646)
		(layer "In6.Cu")
		(net "M_C_CPU1_SB_DQS_DN<3>")
	)
	(segment
		(start 35.789362 -200.290938)
		(end 35.519614 -200.560686)
		(width 0.18288)
		(layer "In6.Cu")
		(net "M_C_CPU1_SB_DQS_DN<3>")
	)
	(segment
		(start 87.770716 -226.017328)
		(end 87.770716 -226.003104)
		(width 0.088646)
		(layer "In6.Cu")
		(net "M_C_CPU1_SB_DQS_DN<3>")
	)
	(segment
		(start 93.597222 -227.969318)
		(end 93.596968 -227.969318)
		(width 0.088646)
		(layer "In6.Cu")
		(net "M_C_CPU1_SB_DQS_DN<3>")
	)
	(segment
		(start 58.47207 -199.341994)
		(end 57.92343 -199.341994)
		(width 0.18288)
		(layer "In6.Cu")
		(net "M_C_CPU1_SB_DQS_DN<3>")
	)
	(segment
		(start 36.421314 -200.436226)
		(end 36.276026 -200.290938)
		(width 0.18288)
		(layer "In6.Cu")
		(net "M_C_CPU1_SB_DQS_DN<3>")
	)
	(segment
		(start 57.25033 -199.466454)
		(end 57.12587 -199.341994)
		(width 0.18288)
		(layer "In6.Cu")
		(net "M_C_CPU1_SB_DQS_DN<3>")
	)
	(segment
		(start 48.310292 -198.857108)
		(end 47.4218 -198.857108)
		(width 0.18288)
		(layer "In6.Cu")
		(net "M_C_CPU1_SB_DQS_DN<3>")
	)
	(segment
		(start 39.23792 -198.57847)
		(end 38.96233 -198.85406)
		(width 0.18288)
		(layer "In6.Cu")
		(net "M_C_CPU1_SB_DQS_DN<3>")
	)
	(segment
		(start 34.883598 -200.560686)
		(end 34.463228 -200.140316)
		(width 0.18288)
		(layer "In6.Cu")
		(net "M_C_CPU1_SB_DQS_DN<3>")
	)
	(segment
		(start 50.860706 -197.741032)
		(end 50.585878 -198.01586)
		(width 0.18288)
		(layer "In6.Cu")
		(net "M_C_CPU1_SB_DQS_DN<3>")
	)
	(segment
		(start 56.45277 -199.466454)
		(end 55.90413 -199.466454)
		(width 0.18288)
		(layer "In6.Cu")
		(net "M_C_CPU1_SB_DQS_DN<3>")
	)
	(segment
		(start 57.12587 -199.341994)
		(end 56.57723 -199.341994)
		(width 0.18288)
		(layer "In6.Cu")
		(net "M_C_CPU1_SB_DQS_DN<3>")
	)
	(segment
		(start 69.126608 -205.858364)
		(end 69.126608 -205.682342)
		(width 0.18288)
		(layer "In6.Cu")
		(net "M_C_CPU1_SB_DQS_DN<3>")
	)
	(segment
		(start 55.90413 -199.466454)
		(end 55.77967 -199.341994)
		(width 0.18288)
		(layer "In6.Cu")
		(net "M_C_CPU1_SB_DQS_DN<3>")
	)
	(segment
		(start 32.59963 -200.124822)
		(end 32.13481 -200.124822)
		(width 0.18288)
		(layer "In6.Cu")
		(net "M_C_CPU1_SB_DQS_DN<3>")
	)
	(segment
		(start 44.637452 -198.254366)
		(end 42.47769 -199.149208)
		(width 0.18288)
		(layer "In6.Cu")
		(net "M_C_CPU1_SB_DQS_DN<3>")
	)
	(segment
		(start 38.641782 -198.85406)
		(end 37.731446 -199.23125)
		(width 0.18288)
		(layer "In6.Cu")
		(net "M_C_CPU1_SB_DQS_DN<3>")
	)
	(segment
		(start 68.562474 -205.29423)
		(end 68.174616 -204.906372)
		(width 0.18288)
		(layer "In6.Cu")
		(net "M_C_CPU1_SB_DQS_DN<3>")
	)
	(segment
		(start 35.519614 -200.560686)
		(end 34.883598 -200.560686)
		(width 0.18288)
		(layer "In6.Cu")
		(net "M_C_CPU1_SB_DQS_DN<3>")
	)
	(segment
		(start 83.250278 -223.48063)
		(end 82.939382 -223.169734)
		(width 0.088646)
		(layer "In6.Cu")
		(net "M_C_CPU1_SB_DQS_DN<3>")
	)
	(segment
		(start 55.77967 -199.341994)
		(end 55.23103 -199.341994)
		(width 0.18288)
		(layer "In6.Cu")
		(net "M_C_CPU1_SB_DQS_DN<3>")
	)
	(segment
		(start 39.59987 -198.57847)
		(end 39.23792 -198.57847)
		(width 0.18288)
		(layer "In6.Cu")
		(net "M_C_CPU1_SB_DQS_DN<3>")
	)
	(segment
		(start 84.590382 -225.468434)
		(end 83.250278 -224.12833)
		(width 0.088646)
		(layer "In6.Cu")
		(net "M_C_CPU1_SB_DQS_DN<3>")
	)
	(segment
		(start 53.68036 -199.038972)
		(end 53.680106 -198.86295)
		(width 0.18288)
		(layer "In6.Cu")
		(net "M_C_CPU1_SB_DQS_DN<3>")
	)
	(segment
		(start 82.5627 -223.169734)
		(end 82.50301 -223.110044)
		(width 0.088646)
		(layer "In6.Cu")
		(net "M_C_CPU1_SB_DQS_DN<3>")
	)
	(segment
		(start 87.958168 -226.341686)
		(end 87.949278 -226.336606)
		(width 0.088646)
		(layer "In6.Cu")
		(net "M_C_CPU1_SB_DQS_DN<3>")
	)
	(segment
		(start 65.941194 -203.088494)
		(end 65.51676 -202.66406)
		(width 0.18288)
		(layer "In6.Cu")
		(net "M_C_CPU1_SB_DQS_DN<3>")
	)
	(segment
		(start 38.96233 -198.85406)
		(end 38.641782 -198.85406)
		(width 0.18288)
		(layer "In6.Cu")
		(net "M_C_CPU1_SB_DQS_DN<3>")
	)
	(segment
		(start 64.952626 -202.099672)
		(end 64.564768 -201.711814)
		(width 0.18288)
		(layer "In6.Cu")
		(net "M_C_CPU1_SB_DQS_DN<3>")
	)
	(segment
		(start 36.52647 -200.436226)
		(end 36.421314 -200.436226)
		(width 0.18288)
		(layer "In6.Cu")
		(net "M_C_CPU1_SB_DQS_DN<3>")
	)
	(segment
		(start 92.657168 -227.969318)
		(end 92.648278 -227.964238)
		(width 0.088646)
		(layer "In6.Cu")
		(net "M_C_CPU1_SB_DQS_DN<3>")
	)
	(segment
		(start 52.635912 -197.995286)
		(end 51.51628 -197.995286)
		(width 0.18288)
		(layer "In6.Cu")
		(net "M_C_CPU1_SB_DQS_DN<3>")
	)
	(segment
		(start 93.971872 -227.969572)
		(end 93.971618 -227.969318)
		(width 0.088646)
		(layer "In6.Cu")
		(net "M_C_CPU1_SB_DQS_DN<3>")
	)
	(segment
		(start 50.585878 -198.01586)
		(end 50.341022 -198.01586)
		(width 0.18288)
		(layer "In6.Cu")
		(net "M_C_CPU1_SB_DQS_DN<3>")
	)
	(segment
		(start 85.057996 -225.51898)
		(end 85.033358 -225.533458)
		(width 0.088646)
		(layer "In6.Cu")
		(net "M_C_CPU1_SB_DQS_DN<3>")
	)
	(segment
		(start 68.174616 -204.73035)
		(end 67.786504 -204.342238)
		(width 0.18288)
		(layer "In6.Cu")
		(net "M_C_CPU1_SB_DQS_DN<3>")
	)
	(segment
		(start 53.680106 -198.86295)
		(end 53.291994 -198.474838)
		(width 0.18288)
		(layer "In6.Cu")
		(net "M_C_CPU1_SB_DQS_DN<3>")
	)
	(segment
		(start 46.768258 -198.590916)
		(end 46.50105 -198.858124)
		(width 0.18288)
		(layer "In6.Cu")
		(net "M_C_CPU1_SB_DQS_DN<3>")
	)
	(segment
		(start 53.291994 -198.474838)
		(end 53.115972 -198.474838)
		(width 0.18288)
		(layer "In6.Cu")
		(net "M_C_CPU1_SB_DQS_DN<3>")
	)
	(segment
		(start 86.937596 -225.51898)
		(end 86.922864 -225.527616)
		(width 0.088646)
		(layer "In6.Cu")
		(net "M_C_CPU1_SB_DQS_DN<3>")
	)
	(segment
		(start 83.250278 -224.12833)
		(end 83.250278 -223.48063)
		(width 0.088646)
		(layer "In6.Cu")
		(net "M_C_CPU1_SB_DQS_DN<3>")
	)
	(segment
		(start 94.723966 -227.64496)
		(end 94.692216 -227.760784)
		(width 0.088646)
		(layer "In6.Cu")
		(net "M_C_CPU1_SB_DQS_DN<3>")
	)
	(segment
		(start 51.51628 -197.995286)
		(end 51.262026 -197.741032)
		(width 0.18288)
		(layer "In6.Cu")
		(net "M_C_CPU1_SB_DQS_DN<3>")
	)
	(segment
		(start 45.627544 -198.622412)
		(end 45.391832 -198.386446)
		(width 0.18288)
		(layer "In6.Cu")
		(net "M_C_CPU1_SB_DQS_DN<3>")
	)
	(segment
		(start 57.92343 -199.341994)
		(end 57.79897 -199.466454)
		(width 0.18288)
		(layer "In6.Cu")
		(net "M_C_CPU1_SB_DQS_DN<3>")
	)
	(segment
		(start 94.692216 -227.760784)
		(end 94.653354 -227.782882)
		(width 0.088646)
		(layer "In6.Cu")
		(net "M_C_CPU1_SB_DQS_DN<3>")
	)
	(segment
		(start 40.211248 -198.863966)
		(end 39.885366 -198.863966)
		(width 0.18288)
		(layer "In6.Cu")
		(net "M_C_CPU1_SB_DQS_DN<3>")
	)
	(segment
		(start 45.863256 -198.858124)
		(end 45.627544 -198.622412)
		(width 0.18288)
		(layer "In6.Cu")
		(net "M_C_CPU1_SB_DQS_DN<3>")
	)
	(segment
		(start 54.108096 -199.466454)
		(end 53.68036 -199.038972)
		(width 0.18288)
		(layer "In6.Cu")
		(net "M_C_CPU1_SB_DQS_DN<3>")
	)
	(segment
		(start 60.834016 -200.03135)
		(end 60.671456 -200.09866)
		(width 0.18288)
		(layer "In6.Cu")
		(net "M_C_CPU1_SB_DQS_DN<3>")
	)
	(segment
		(start 61.408564 -200.404222)
		(end 61.341254 -200.241408)
		(width 0.18288)
		(layer "In6.Cu")
		(net "M_C_CPU1_SB_DQS_DN<3>")
	)
	(segment
		(start 42.47769 -199.149208)
		(end 40.900096 -199.149208)
		(width 0.18288)
		(layer "In6.Cu")
		(net "M_C_CPU1_SB_DQS_DN<3>")
	)
	(segment
		(start 60.671456 -200.09866)
		(end 59.14517 -199.466454)
		(width 0.18288)
		(layer "In6.Cu")
		(net "M_C_CPU1_SB_DQS_DN<3>")
	)
	(segment
		(start 82.939382 -223.169734)
		(end 82.5627 -223.169734)
		(width 0.088646)
		(layer "In6.Cu")
		(net "M_C_CPU1_SB_DQS_DN<3>")
	)
	(segment
		(start 62.077854 -200.546716)
		(end 61.915294 -200.614026)
		(width 0.18288)
		(layer "In6.Cu")
		(net "M_C_CPU1_SB_DQS_DN<3>")
	)
	(segment
		(start 91.636596 -227.146866)
		(end 91.621864 -227.155502)
		(width 0.088646)
		(layer "In6.Cu")
		(net "M_C_CPU1_SB_DQS_DN<3>")
	)
	(segment
		(start 46.50105 -198.858124)
		(end 45.863256 -198.858124)
		(width 0.18288)
		(layer "In6.Cu")
		(net "M_C_CPU1_SB_DQS_DN<3>")
	)
	(segment
		(start 39.885366 -198.863966)
		(end 39.59987 -198.57847)
		(width 0.18288)
		(layer "In6.Cu")
		(net "M_C_CPU1_SB_DQS_DN<3>")
	)
	(segment
		(start 47.155608 -198.590916)
		(end 46.768258 -198.590916)
		(width 0.18288)
		(layer "In6.Cu")
		(net "M_C_CPU1_SB_DQS_DN<3>")
	)
	(segment
		(start 80.249268 -219.977208)
		(end 71.602346 -211.330286)
		(width 0.18288)
		(layer "In6.Cu")
		(net "M_C_CPU1_SB_DQS_DN<3>")
	)
	(segment
		(start 34.463228 -200.140316)
		(end 33.880044 -199.899016)
		(width 0.18288)
		(layer "In6.Cu")
		(net "M_C_CPU1_SB_DQS_DN<3>")
	)
	(segment
		(start 53.115972 -198.474838)
		(end 52.635912 -197.995286)
		(width 0.18288)
		(layer "In6.Cu")
		(net "M_C_CPU1_SB_DQS_DN<3>")
	)
	(segment
		(start 94.498668 -227.823776)
		(end 94.22511 -227.823776)
		(width 0.088646)
		(layer "In6.Cu")
		(net "M_C_CPU1_SB_DQS_DN<3>")
	)
	(segment
		(start 71.602346 -211.330286)
		(end 69.514466 -206.246222)
		(width 0.18288)
		(layer "In6.Cu")
		(net "M_C_CPU1_SB_DQS_DN<3>")
	)
	(segment
		(start 90.307414 -227.155502)
		(end 90.292682 -227.146866)
		(width 0.088646)
		(layer "In6.Cu")
		(net "M_C_CPU1_SB_DQS_DN<3>")
	)
	(segment
		(start 61.915294 -200.614026)
		(end 61.408564 -200.404222)
		(width 0.18288)
		(layer "In6.Cu")
		(net "M_C_CPU1_SB_DQS_DN<3>")
	)
	(segment
		(start 93.046296 -227.960682)
		(end 93.031564 -227.969318)
		(width 0.088646)
		(layer "In6.Cu")
		(net "M_C_CPU1_SB_DQS_DN<3>")
	)
	(segment
		(start 59.14517 -199.466454)
		(end 58.59653 -199.466454)
		(width 0.18288)
		(layer "In6.Cu")
		(net "M_C_CPU1_SB_DQS_DN<3>")
	)
	(segment
		(start 80.249268 -222.626682)
		(end 80.249268 -219.977208)
		(width 0.18288)
		(layer "In6.Cu")
		(net "M_C_CPU1_SB_DQS_DN<3>")
	)
	(segment
		(start 51.262026 -197.741032)
		(end 50.860706 -197.741032)
		(width 0.18288)
		(layer "In6.Cu")
		(net "M_C_CPU1_SB_DQS_DN<3>")
	)
	(segment
		(start 58.59653 -199.466454)
		(end 58.47207 -199.341994)
		(width 0.18288)
		(layer "In6.Cu")
		(net "M_C_CPU1_SB_DQS_DN<3>")
	)
	(segment
		(start 92.193364 -227.159058)
		(end 92.187268 -227.155502)
		(width 0.088646)
		(layer "In6.Cu")
		(net "M_C_CPU1_SB_DQS_DN<3>")
	)
	(segment
		(start 89.367614 -227.155502)
		(end 89.352882 -227.146866)
		(width 0.088646)
		(layer "In6.Cu")
		(net "M_C_CPU1_SB_DQS_DN<3>")
	)
	(segment
		(start 61.341254 -200.241408)
		(end 60.834016 -200.03135)
		(width 0.18288)
		(layer "In6.Cu")
		(net "M_C_CPU1_SB_DQS_DN<3>")
	)
	(segment
		(start 63.321692 -201.062082)
		(end 63.159132 -201.129392)
		(width 0.18288)
		(layer "In6.Cu")
		(net "M_C_CPU1_SB_DQS_DN<3>")
	)
	(segment
		(start 64.564768 -201.711814)
		(end 63.89624 -201.434954)
		(width 0.18288)
		(layer "In6.Cu")
		(net "M_C_CPU1_SB_DQS_DN<3>")
	)
	(segment
		(start 63.828676 -201.271886)
		(end 63.321692 -201.062082)
		(width 0.18288)
		(layer "In6.Cu")
		(net "M_C_CPU1_SB_DQS_DN<3>")
	)
	(segment
		(start 88.240616 -226.83978)
		(end 88.240616 -226.821238)
		(width 0.088646)
		(layer "In6.Cu")
		(net "M_C_CPU1_SB_DQS_DN<3>")
	)
	(segment
		(start 32.13481 -200.124822)
		(end 31.876746 -199.866758)
		(width 0.18288)
		(layer "In6.Cu")
		(net "M_C_CPU1_SB_DQS_DN<3>")
	)
	(segment
		(start 80.73263 -223.110044)
		(end 80.249268 -222.626682)
		(width 0.18288)
		(layer "In6.Cu")
		(net "M_C_CPU1_SB_DQS_DN<3>")
	)
	(segment
		(start 33.880044 -199.899016)
		(end 33.144714 -199.899016)
		(width 0.18288)
		(layer "In6.Cu")
		(net "M_C_CPU1_SB_DQS_DN<3>")
	)
	(segment
		(start 68.174616 -204.906372)
		(end 68.174616 -204.73035)
		(width 0.18288)
		(layer "In6.Cu")
		(net "M_C_CPU1_SB_DQS_DN<3>")
	)
	(segment
		(start 37.731446 -199.23125)
		(end 36.52647 -200.436226)
		(width 0.18288)
		(layer "In6.Cu")
		(net "M_C_CPU1_SB_DQS_DN<3>")
	)
	(segment
		(start 62.652402 -200.919588)
		(end 62.585092 -200.756774)
		(width 0.18288)
		(layer "In6.Cu")
		(net "M_C_CPU1_SB_DQS_DN<3>")
	)
	(segment
		(start 62.585092 -200.756774)
		(end 62.077854 -200.546716)
		(width 0.18288)
		(layer "In6.Cu")
		(net "M_C_CPU1_SB_DQS_DN<3>")
	)
	(segment
		(start 91.247468 -227.155502)
		(end 91.237054 -227.149406)
		(width 0.088646)
		(layer "In6.Cu")
		(net "M_C_CPU1_SB_DQS_DN<3>")
	)
	(segment
		(start 68.738496 -205.29423)
		(end 68.562474 -205.29423)
		(width 0.18288)
		(layer "In6.Cu")
		(net "M_C_CPU1_SB_DQS_DN<3>")
	)
	(segment
		(start 69.514466 -206.246222)
		(end 69.126608 -205.858364)
		(width 0.18288)
		(layer "In6.Cu")
		(net "M_C_CPU1_SB_DQS_DN<3>")
	)
	(segment
		(start 36.276026 -200.290938)
		(end 35.789362 -200.290938)
		(width 0.18288)
		(layer "In6.Cu")
		(net "M_C_CPU1_SB_DQS_DN<3>")
	)
	(segment
		(start 67.786504 -204.342238)
		(end 67.610482 -204.342238)
		(width 0.18288)
		(layer "In6.Cu")
		(net "M_C_CPU1_SB_DQS_DN<3>")
	)
	(segment
		(start 47.4218 -198.857108)
		(end 47.155608 -198.590916)
		(width 0.18288)
		(layer "In6.Cu")
		(net "M_C_CPU1_SB_DQS_DN<3>")
	)
	(segment
		(start 56.57723 -199.341994)
		(end 56.45277 -199.466454)
		(width 0.18288)
		(layer "In6.Cu")
		(net "M_C_CPU1_SB_DQS_DN<3>")
	)
	(segment
		(start 55.10657 -199.466454)
		(end 54.108096 -199.466454)
		(width 0.18288)
		(layer "In6.Cu")
		(net "M_C_CPU1_SB_DQS_DN<3>")
	)
	(segment
		(start 45.0723 -198.254366)
		(end 44.637452 -198.254366)
		(width 0.18288)
		(layer "In6.Cu")
		(net "M_C_CPU1_SB_DQS_DN<3>")
	)
	(segment
		(start 94.22511 -227.823776)
		(end 93.971872 -227.969572)
		(width 0.088646)
		(layer "In6.Cu")
		(net "M_C_CPU1_SB_DQS_DN<3>")
	)
	(segment
		(start 82.50301 -223.110044)
		(end 82.479642 -223.110044)
		(width 0.088646)
		(layer "In6.Cu")
		(net "M_C_CPU1_SB_DQS_DN<3>")
	)
	(segment
		(start 50.341022 -198.01586)
		(end 48.310292 -198.857108)
		(width 0.18288)
		(layer "In6.Cu")
		(net "M_C_CPU1_SB_DQS_DN<3>")
	)
	(segment
		(start 33.144714 -199.899016)
		(end 32.59963 -200.124822)
		(width 0.18288)
		(layer "In6.Cu")
		(net "M_C_CPU1_SB_DQS_DN<3>")
	)
	(segment
		(start 57.79897 -199.466454)
		(end 57.25033 -199.466454)
		(width 0.18288)
		(layer "In6.Cu")
		(net "M_C_CPU1_SB_DQS_DN<3>")
	)
	(segment
		(start 55.23103 -199.341994)
		(end 55.10657 -199.466454)
		(width 0.18288)
		(layer "In6.Cu")
		(net "M_C_CPU1_SB_DQS_DN<3>")
	)
	(segment
		(start 66.356738 -203.088494)
		(end 65.941194 -203.088494)
		(width 0.18288)
		(layer "In6.Cu")
		(net "M_C_CPU1_SB_DQS_DN<3>")
	)
	(segment
		(start 63.159132 -201.129392)
		(end 62.652402 -200.919588)
		(width 0.18288)
		(layer "In6.Cu")
		(net "M_C_CPU1_SB_DQS_DN<3>")
	)
	(segment
		(start 69.126608 -205.682342)
		(end 68.738496 -205.29423)
		(width 0.18288)
		(layer "In6.Cu")
		(net "M_C_CPU1_SB_DQS_DN<3>")
	)
	(arc
		(start 92.469716 -227.64496)
		(mid 92.3958 -227.365458)
		(end 92.193364 -227.159058)
		(width 0.088646)
		(layer "In6.Cu")
		(net "M_C_CPU1_SB_DQS_DN<3>")
	)
	(arc
		(start 91.237054 -227.149406)
		(mid 90.958622 -227.07956)
		(end 90.68181 -227.155502)
		(width 0.088646)
		(layer "In6.Cu")
		(net "M_C_CPU1_SB_DQS_DN<3>")
	)
	(arc
		(start 88.427814 -227.155502)
		(mid 88.292881 -227.022148)
		(end 88.240616 -226.83978)
		(width 0.088646)
		(layer "In6.Cu")
		(net "M_C_CPU1_SB_DQS_DN<3>")
	)
	(arc
		(start 85.608668 -225.527616)
		(mid 85.334439 -225.451691)
		(end 85.057996 -225.51898)
		(width 0.088646)
		(layer "In6.Cu")
		(net "M_C_CPU1_SB_DQS_DN<3>")
	)
	(arc
		(start 86.922864 -225.527616)
		(mid 86.735666 -225.577759)
		(end 86.548468 -225.527616)
		(width 0.088646)
		(layer "In6.Cu")
		(net "M_C_CPU1_SB_DQS_DN<3>")
	)
	(arc
		(start 88.240616 -226.821238)
		(mid 88.162505 -226.544289)
		(end 87.958168 -226.341686)
		(width 0.088646)
		(layer "In6.Cu")
		(net "M_C_CPU1_SB_DQS_DN<3>")
	)
	(arc
		(start 88.80221 -227.155502)
		(mid 88.615012 -227.205645)
		(end 88.427814 -227.155502)
		(width 0.088646)
		(layer "In6.Cu")
		(net "M_C_CPU1_SB_DQS_DN<3>")
	)
	(arc
		(start 87.488268 -225.527616)
		(mid 87.214039 -225.451691)
		(end 86.937596 -225.51898)
		(width 0.088646)
		(layer "In6.Cu")
		(net "M_C_CPU1_SB_DQS_DN<3>")
	)
	(arc
		(start 89.74201 -227.155502)
		(mid 89.554812 -227.205645)
		(end 89.367614 -227.155502)
		(width 0.088646)
		(layer "In6.Cu")
		(net "M_C_CPU1_SB_DQS_DN<3>")
	)
	(arc
		(start 84.66836 -225.527616)
		(mid 84.661585 -225.523625)
		(end 84.654898 -225.519488)
		(width 0.088646)
		(layer "In6.Cu")
		(net "M_C_CPU1_SB_DQS_DN<3>")
	)
	(arc
		(start 90.292682 -227.146866)
		(mid 90.016207 -227.079546)
		(end 89.74201 -227.155502)
		(width 0.088646)
		(layer "In6.Cu")
		(net "M_C_CPU1_SB_DQS_DN<3>")
	)
	(arc
		(start 92.648278 -227.964238)
		(mid 92.517364 -227.827878)
		(end 92.469716 -227.64496)
		(width 0.088646)
		(layer "In6.Cu")
		(net "M_C_CPU1_SB_DQS_DN<3>")
	)
	(arc
		(start 85.983064 -225.527616)
		(mid 85.795866 -225.577759)
		(end 85.608668 -225.527616)
		(width 0.088646)
		(layer "In6.Cu")
		(net "M_C_CPU1_SB_DQS_DN<3>")
	)
	(arc
		(start 93.971618 -227.969318)
		(mid 93.78442 -228.019461)
		(end 93.597222 -227.969318)
		(width 0.088646)
		(layer "In6.Cu")
		(net "M_C_CPU1_SB_DQS_DN<3>")
	)
	(arc
		(start 92.187268 -227.155502)
		(mid 91.913069 -227.079667)
		(end 91.636596 -227.146866)
		(width 0.088646)
		(layer "In6.Cu")
		(net "M_C_CPU1_SB_DQS_DN<3>")
	)
	(arc
		(start 93.031564 -227.969318)
		(mid 92.844366 -228.019461)
		(end 92.657168 -227.969318)
		(width 0.088646)
		(layer "In6.Cu")
		(net "M_C_CPU1_SB_DQS_DN<3>")
	)
	(arc
		(start 87.770716 -226.003104)
		(mid 87.691575 -225.728481)
		(end 87.488268 -225.527616)
		(width 0.088646)
		(layer "In6.Cu")
		(net "M_C_CPU1_SB_DQS_DN<3>")
	)
	(arc
		(start 91.621864 -227.155502)
		(mid 91.434666 -227.205645)
		(end 91.247468 -227.155502)
		(width 0.088646)
		(layer "In6.Cu")
		(net "M_C_CPU1_SB_DQS_DN<3>")
	)
	(arc
		(start 86.548468 -225.527616)
		(mid 86.265766 -225.451874)
		(end 85.983064 -225.527616)
		(width 0.088646)
		(layer "In6.Cu")
		(net "M_C_CPU1_SB_DQS_DN<3>")
	)
	(arc
		(start 87.949278 -226.336606)
		(mid 87.818364 -226.200246)
		(end 87.770716 -226.017328)
		(width 0.088646)
		(layer "In6.Cu")
		(net "M_C_CPU1_SB_DQS_DN<3>")
	)
	(arc
		(start 93.596968 -227.969318)
		(mid 93.322739 -227.893393)
		(end 93.046296 -227.960682)
		(width 0.088646)
		(layer "In6.Cu")
		(net "M_C_CPU1_SB_DQS_DN<3>")
	)
	(arc
		(start 85.031326 -225.534474)
		(mid 84.848961 -225.577917)
		(end 84.66836 -225.527616)
		(width 0.088646)
		(layer "In6.Cu")
		(net "M_C_CPU1_SB_DQS_DN<3>")
	)
	(arc
		(start 90.68181 -227.155502)
		(mid 90.494612 -227.205645)
		(end 90.307414 -227.155502)
		(width 0.088646)
		(layer "In6.Cu")
		(net "M_C_CPU1_SB_DQS_DN<3>")
	)
	(arc
		(start 94.653354 -227.782882)
		(mid 94.578669 -227.813387)
		(end 94.498668 -227.823776)
		(width 0.088646)
		(layer "In6.Cu")
		(net "M_C_CPU1_SB_DQS_DN<3>")
	)
	(arc
		(start 89.352882 -227.146866)
		(mid 89.076407 -227.079546)
		(end 88.80221 -227.155502)
		(width 0.088646)
		(layer "In6.Cu")
		(net "M_C_CPU1_SB_DQS_DN<3>")
	)
	(arc
		(start 84.654898 -225.519488)
		(mid 84.621233 -225.495738)
		(end 84.590382 -225.468434)
		(width 0.088646)
		(layer "In6.Cu")
		(net "M_C_CPU1_SB_DQS_DN<3>")
	)
	(segment
		(start 29.557472 -209.477864)
		(end 29.964126 -209.477864)
		(width 0.20066)
		(layer "F.Cu")
		(net "M_C_CPU1_SB_DQS_DN<2>")
	)
	(segment
		(start 23.776686 -209.216752)
		(end 24.037798 -209.477864)
		(width 0.20066)
		(layer "F.Cu")
		(net "M_C_CPU1_SB_DQS_DN<2>")
	)
	(segment
		(start 26.20391 -209.631026)
		(end 26.204672 -209.631026)
		(width 0.101854)
		(layer "F.Cu")
		(net "M_C_CPU1_SB_DQS_DN<2>")
	)
	(segment
		(start 30.225238 -209.216752)
		(end 30.771846 -209.216752)
		(width 0.20066)
		(layer "F.Cu")
		(net "M_C_CPU1_SB_DQS_DN<2>")
	)
	(segment
		(start 29.964126 -209.477864)
		(end 30.225238 -209.216752)
		(width 0.20066)
		(layer "F.Cu")
		(net "M_C_CPU1_SB_DQS_DN<2>")
	)
	(segment
		(start 26.204672 -209.631026)
		(end 26.21534 -209.641694)
		(width 0.101854)
		(layer "F.Cu")
		(net "M_C_CPU1_SB_DQS_DN<2>")
	)
	(segment
		(start 28.68422 -209.641694)
		(end 28.945586 -209.90306)
		(width 0.20066)
		(layer "F.Cu")
		(net "M_C_CPU1_SB_DQS_DN<2>")
	)
	(segment
		(start 24.037798 -209.477864)
		(end 24.55164 -209.477864)
		(width 0.20066)
		(layer "F.Cu")
		(net "M_C_CPU1_SB_DQS_DN<2>")
	)
	(segment
		(start 29.132276 -209.90306)
		(end 29.557472 -209.477864)
		(width 0.20066)
		(layer "F.Cu")
		(net "M_C_CPU1_SB_DQS_DN<2>")
	)
	(segment
		(start 28.529026 -209.641694)
		(end 28.68422 -209.641694)
		(width 0.20066)
		(layer "F.Cu")
		(net "M_C_CPU1_SB_DQS_DN<2>")
	)
	(segment
		(start 24.55164 -209.477864)
		(end 25.187656 -209.90306)
		(width 0.20066)
		(layer "F.Cu")
		(net "M_C_CPU1_SB_DQS_DN<2>")
	)
	(segment
		(start 91.434666 -230.622602)
		(end 91.434412 -230.622348)
		(width 0.20066)
		(layer "F.Cu")
		(net "M_C_CPU1_SB_DQS_DN<2>")
	)
	(segment
		(start 91.434412 -230.622348)
		(end 91.434412 -230.086662)
		(width 0.20066)
		(layer "F.Cu")
		(net "M_C_CPU1_SB_DQS_DN<2>")
	)
	(segment
		(start 31.876746 -209.216752)
		(end 30.771846 -209.216752)
		(width 0.20066)
		(layer "F.Cu")
		(net "M_C_CPU1_SB_DQS_DN<2>")
	)
	(segment
		(start 26.21534 -209.641694)
		(end 28.529026 -209.641694)
		(width 0.1016)
		(layer "F.Cu")
		(net "M_C_CPU1_SB_DQS_DN<2>")
	)
	(segment
		(start 25.72766 -209.90306)
		(end 25.999694 -209.631026)
		(width 0.20066)
		(layer "F.Cu")
		(net "M_C_CPU1_SB_DQS_DN<2>")
	)
	(segment
		(start 25.187656 -209.90306)
		(end 25.72766 -209.90306)
		(width 0.20066)
		(layer "F.Cu")
		(net "M_C_CPU1_SB_DQS_DN<2>")
	)
	(segment
		(start 25.999694 -209.631026)
		(end 26.20391 -209.631026)
		(width 0.20066)
		(layer "F.Cu")
		(net "M_C_CPU1_SB_DQS_DN<2>")
	)
	(segment
		(start 28.945586 -209.90306)
		(end 29.132276 -209.90306)
		(width 0.20066)
		(layer "F.Cu")
		(net "M_C_CPU1_SB_DQS_DN<2>")
	)
	(segment
		(start 23.228046 -209.216752)
		(end 23.776686 -209.216752)
		(width 0.20066)
		(layer "F.Cu")
		(net "M_C_CPU1_SB_DQS_DN<2>")
	)
	(segment
		(start 65.7098 -212.46973)
		(end 65.58534 -212.34527)
		(width 0.18288)
		(layer "In4.Cu")
		(net "M_C_CPU1_SB_DQS_DN<2>")
	)
	(segment
		(start 70.251828 -220.99016)
		(end 70.042024 -220.48343)
		(width 0.18288)
		(layer "In4.Cu")
		(net "M_C_CPU1_SB_DQS_DN<2>")
	)
	(segment
		(start 85.608414 -230.41102)
		(end 85.593682 -230.402384)
		(width 0.088646)
		(layer "In4.Cu")
		(net "M_C_CPU1_SB_DQS_DN<2>")
	)
	(segment
		(start 54.899814 -211.624164)
		(end 51.520344 -211.624164)
		(width 0.18288)
		(layer "In4.Cu")
		(net "M_C_CPU1_SB_DQS_DN<2>")
	)
	(segment
		(start 47.425864 -212.46465)
		(end 47.153068 -212.191854)
		(width 0.18288)
		(layer "In4.Cu")
		(net "M_C_CPU1_SB_DQS_DN<2>")
	)
	(segment
		(start 44.563284 -211.685632)
		(end 43.653202 -210.77555)
		(width 0.18288)
		(layer "In4.Cu")
		(net "M_C_CPU1_SB_DQS_DN<2>")
	)
	(segment
		(start 88.427814 -230.41102)
		(end 88.413082 -230.402384)
		(width 0.088646)
		(layer "In4.Cu")
		(net "M_C_CPU1_SB_DQS_DN<2>")
	)
	(segment
		(start 40.605456 -210.77555)
		(end 39.747952 -209.918046)
		(width 0.18288)
		(layer "In4.Cu")
		(net "M_C_CPU1_SB_DQS_DN<2>")
	)
	(segment
		(start 69.736208 -219.746322)
		(end 69.526404 -219.239592)
		(width 0.18288)
		(layer "In4.Cu")
		(net "M_C_CPU1_SB_DQS_DN<2>")
	)
	(segment
		(start 45.182282 -211.685632)
		(end 44.563284 -211.685632)
		(width 0.18288)
		(layer "In4.Cu")
		(net "M_C_CPU1_SB_DQS_DN<2>")
	)
	(segment
		(start 36.510468 -209.918046)
		(end 36.234116 -209.641694)
		(width 0.18288)
		(layer "In4.Cu")
		(net "M_C_CPU1_SB_DQS_DN<2>")
	)
	(segment
		(start 69.011038 -217.995754)
		(end 69.078348 -217.833194)
		(width 0.18288)
		(layer "In4.Cu")
		(net "M_C_CPU1_SB_DQS_DN<2>")
	)
	(segment
		(start 90.307668 -230.41102)
		(end 90.297254 -230.404924)
		(width 0.088646)
		(layer "In4.Cu")
		(net "M_C_CPU1_SB_DQS_DN<2>")
	)
	(segment
		(start 35.514788 -209.906616)
		(end 35.041586 -209.906616)
		(width 0.18288)
		(layer "In4.Cu")
		(net "M_C_CPU1_SB_DQS_DN<2>")
	)
	(segment
		(start 90.935556 -230.265478)
		(end 90.682064 -230.41102)
		(width 0.088646)
		(layer "In4.Cu")
		(net "M_C_CPU1_SB_DQS_DN<2>")
	)
	(segment
		(start 35.041586 -209.906616)
		(end 34.406078 -209.271108)
		(width 0.18288)
		(layer "In4.Cu")
		(net "M_C_CPU1_SB_DQS_DN<2>")
	)
	(segment
		(start 67.15887 -213.527132)
		(end 66.868294 -212.825584)
		(width 0.18288)
		(layer "In4.Cu")
		(net "M_C_CPU1_SB_DQS_DN<2>")
	)
	(segment
		(start 51.520344 -211.624164)
		(end 51.237896 -211.341716)
		(width 0.18288)
		(layer "In4.Cu")
		(net "M_C_CPU1_SB_DQS_DN<2>")
	)
	(segment
		(start 77.706728 -229.173786)
		(end 70.767194 -222.233998)
		(width 0.18288)
		(layer "In4.Cu")
		(net "M_C_CPU1_SB_DQS_DN<2>")
	)
	(segment
		(start 70.042024 -220.48343)
		(end 70.109334 -220.32087)
		(width 0.18288)
		(layer "In4.Cu")
		(net "M_C_CPU1_SB_DQS_DN<2>")
	)
	(segment
		(start 70.6247 -221.564708)
		(end 70.414642 -221.05747)
		(width 0.18288)
		(layer "In4.Cu")
		(net "M_C_CPU1_SB_DQS_DN<2>")
	)
	(segment
		(start 50.868834 -211.341716)
		(end 50.603912 -211.606638)
		(width 0.18288)
		(layer "In4.Cu")
		(net "M_C_CPU1_SB_DQS_DN<2>")
	)
	(segment
		(start 91.333828 -230.228394)
		(end 91.192604 -230.265478)
		(width 0.088646)
		(layer "In4.Cu")
		(net "M_C_CPU1_SB_DQS_DN<2>")
	)
	(segment
		(start 70.767194 -222.233998)
		(end 70.55739 -221.727268)
		(width 0.18288)
		(layer "In4.Cu")
		(net "M_C_CPU1_SB_DQS_DN<2>")
	)
	(segment
		(start 55.67299 -210.850988)
		(end 54.899814 -211.624164)
		(width 0.18288)
		(layer "In4.Cu")
		(net "M_C_CPU1_SB_DQS_DN<2>")
	)
	(segment
		(start 68.705476 -217.258646)
		(end 68.495672 -216.751916)
		(width 0.18288)
		(layer "In4.Cu")
		(net "M_C_CPU1_SB_DQS_DN<2>")
	)
	(segment
		(start 67.531996 -214.10168)
		(end 67.321938 -213.594442)
		(width 0.18288)
		(layer "In4.Cu")
		(net "M_C_CPU1_SB_DQS_DN<2>")
	)
	(segment
		(start 67.464686 -214.26424)
		(end 67.531996 -214.10168)
		(width 0.18288)
		(layer "In4.Cu")
		(net "M_C_CPU1_SB_DQS_DN<2>")
	)
	(segment
		(start 50.175922 -211.606638)
		(end 49.31791 -212.46465)
		(width 0.18288)
		(layer "In4.Cu")
		(net "M_C_CPU1_SB_DQS_DN<2>")
	)
	(segment
		(start 69.526404 -219.239592)
		(end 69.593714 -219.077032)
		(width 0.18288)
		(layer "In4.Cu")
		(net "M_C_CPU1_SB_DQS_DN<2>")
	)
	(segment
		(start 69.078348 -217.833194)
		(end 68.86829 -217.325956)
		(width 0.18288)
		(layer "In4.Cu")
		(net "M_C_CPU1_SB_DQS_DN<2>")
	)
	(segment
		(start 68.047362 -215.345518)
		(end 67.837304 -214.83828)
		(width 0.18288)
		(layer "In4.Cu")
		(net "M_C_CPU1_SB_DQS_DN<2>")
	)
	(segment
		(start 68.495672 -216.751916)
		(end 68.562982 -216.589356)
		(width 0.18288)
		(layer "In4.Cu")
		(net "M_C_CPU1_SB_DQS_DN<2>")
	)
	(segment
		(start 36.234116 -209.641694)
		(end 35.77971 -209.641694)
		(width 0.18288)
		(layer "In4.Cu")
		(net "M_C_CPU1_SB_DQS_DN<2>")
	)
	(segment
		(start 49.31791 -212.46465)
		(end 47.425864 -212.46465)
		(width 0.18288)
		(layer "In4.Cu")
		(net "M_C_CPU1_SB_DQS_DN<2>")
	)
	(segment
		(start 66.868294 -212.825584)
		(end 66.51244 -212.46973)
		(width 0.18288)
		(layer "In4.Cu")
		(net "M_C_CPU1_SB_DQS_DN<2>")
	)
	(segment
		(start 51.237896 -211.341716)
		(end 50.868834 -211.341716)
		(width 0.18288)
		(layer "In4.Cu")
		(net "M_C_CPU1_SB_DQS_DN<2>")
	)
	(segment
		(start 32.135318 -209.475324)
		(end 31.876746 -209.216752)
		(width 0.18288)
		(layer "In4.Cu")
		(net "M_C_CPU1_SB_DQS_DN<2>")
	)
	(segment
		(start 69.220842 -218.502484)
		(end 69.011038 -217.995754)
		(width 0.18288)
		(layer "In4.Cu")
		(net "M_C_CPU1_SB_DQS_DN<2>")
	)
	(segment
		(start 87.488014 -230.41102)
		(end 87.473282 -230.402384)
		(width 0.088646)
		(layer "In4.Cu")
		(net "M_C_CPU1_SB_DQS_DN<2>")
	)
	(segment
		(start 83.989672 -230.169974)
		(end 83.584288 -229.76459)
		(width 0.088646)
		(layer "In4.Cu")
		(net "M_C_CPU1_SB_DQS_DN<2>")
	)
	(segment
		(start 65.58534 -212.34527)
		(end 65.0367 -212.34527)
		(width 0.18288)
		(layer "In4.Cu")
		(net "M_C_CPU1_SB_DQS_DN<2>")
	)
	(segment
		(start 50.603912 -211.606638)
		(end 50.175922 -211.606638)
		(width 0.18288)
		(layer "In4.Cu")
		(net "M_C_CPU1_SB_DQS_DN<2>")
	)
	(segment
		(start 86.548214 -230.41102)
		(end 86.533482 -230.402384)
		(width 0.088646)
		(layer "In4.Cu")
		(net "M_C_CPU1_SB_DQS_DN<2>")
	)
	(segment
		(start 32.75203 -209.475324)
		(end 32.135318 -209.475324)
		(width 0.18288)
		(layer "In4.Cu")
		(net "M_C_CPU1_SB_DQS_DN<2>")
	)
	(segment
		(start 67.980052 -215.508078)
		(end 68.047362 -215.345518)
		(width 0.18288)
		(layer "In4.Cu")
		(net "M_C_CPU1_SB_DQS_DN<2>")
	)
	(segment
		(start 88.808306 -230.407718)
		(end 88.803988 -230.410258)
		(width 0.088646)
		(layer "In4.Cu")
		(net "M_C_CPU1_SB_DQS_DN<2>")
	)
	(segment
		(start 88.802464 -230.41102)
		(end 88.798654 -230.413306)
		(width 0.088646)
		(layer "In4.Cu")
		(net "M_C_CPU1_SB_DQS_DN<2>")
	)
	(segment
		(start 70.109334 -220.32087)
		(end 69.899276 -219.813632)
		(width 0.18288)
		(layer "In4.Cu")
		(net "M_C_CPU1_SB_DQS_DN<2>")
	)
	(segment
		(start 32.956246 -209.271108)
		(end 32.75203 -209.475324)
		(width 0.18288)
		(layer "In4.Cu")
		(net "M_C_CPU1_SB_DQS_DN<2>")
	)
	(segment
		(start 67.67449 -214.77097)
		(end 67.464686 -214.26424)
		(width 0.18288)
		(layer "In4.Cu")
		(net "M_C_CPU1_SB_DQS_DN<2>")
	)
	(segment
		(start 39.747952 -209.918046)
		(end 36.510468 -209.918046)
		(width 0.18288)
		(layer "In4.Cu")
		(net "M_C_CPU1_SB_DQS_DN<2>")
	)
	(segment
		(start 43.653202 -210.77555)
		(end 40.605456 -210.77555)
		(width 0.18288)
		(layer "In4.Cu")
		(net "M_C_CPU1_SB_DQS_DN<2>")
	)
	(segment
		(start 84.668614 -230.41102)
		(end 84.661248 -230.406702)
		(width 0.088646)
		(layer "In4.Cu")
		(net "M_C_CPU1_SB_DQS_DN<2>")
	)
	(segment
		(start 83.584288 -229.76459)
		(end 83.584288 -229.673912)
		(width 0.088646)
		(layer "In4.Cu")
		(net "M_C_CPU1_SB_DQS_DN<2>")
	)
	(segment
		(start 67.837304 -214.83828)
		(end 67.67449 -214.77097)
		(width 0.18288)
		(layer "In4.Cu")
		(net "M_C_CPU1_SB_DQS_DN<2>")
	)
	(segment
		(start 91.192604 -230.265478)
		(end 90.935556 -230.265478)
		(width 0.088646)
		(layer "In4.Cu")
		(net "M_C_CPU1_SB_DQS_DN<2>")
	)
	(segment
		(start 68.352924 -216.082118)
		(end 68.189856 -216.014808)
		(width 0.18288)
		(layer "In4.Cu")
		(net "M_C_CPU1_SB_DQS_DN<2>")
	)
	(segment
		(start 64.169798 -212.46973)
		(end 62.031118 -211.584032)
		(width 0.18288)
		(layer "In4.Cu")
		(net "M_C_CPU1_SB_DQS_DN<2>")
	)
	(segment
		(start 69.899276 -219.813632)
		(end 69.736208 -219.746322)
		(width 0.18288)
		(layer "In4.Cu")
		(net "M_C_CPU1_SB_DQS_DN<2>")
	)
	(segment
		(start 47.153068 -212.191854)
		(end 46.77029 -212.191854)
		(width 0.18288)
		(layer "In4.Cu")
		(net "M_C_CPU1_SB_DQS_DN<2>")
	)
	(segment
		(start 62.031118 -211.584032)
		(end 59.737752 -211.584032)
		(width 0.18288)
		(layer "In4.Cu")
		(net "M_C_CPU1_SB_DQS_DN<2>")
	)
	(segment
		(start 82.708496 -229.173786)
		(end 77.706728 -229.173786)
		(width 0.18288)
		(layer "In4.Cu")
		(net "M_C_CPU1_SB_DQS_DN<2>")
	)
	(segment
		(start 68.189856 -216.014808)
		(end 67.980052 -215.508078)
		(width 0.18288)
		(layer "In4.Cu")
		(net "M_C_CPU1_SB_DQS_DN<2>")
	)
	(segment
		(start 59.004708 -210.850988)
		(end 55.67299 -210.850988)
		(width 0.18288)
		(layer "In4.Cu")
		(net "M_C_CPU1_SB_DQS_DN<2>")
	)
	(segment
		(start 68.86829 -217.325956)
		(end 68.705476 -217.258646)
		(width 0.18288)
		(layer "In4.Cu")
		(net "M_C_CPU1_SB_DQS_DN<2>")
	)
	(segment
		(start 34.406078 -209.271108)
		(end 32.956246 -209.271108)
		(width 0.18288)
		(layer "In4.Cu")
		(net "M_C_CPU1_SB_DQS_DN<2>")
	)
	(segment
		(start 67.321938 -213.594442)
		(end 67.15887 -213.527132)
		(width 0.18288)
		(layer "In4.Cu")
		(net "M_C_CPU1_SB_DQS_DN<2>")
	)
	(segment
		(start 45.952918 -212.456268)
		(end 45.182282 -211.685632)
		(width 0.18288)
		(layer "In4.Cu")
		(net "M_C_CPU1_SB_DQS_DN<2>")
	)
	(segment
		(start 35.77971 -209.641694)
		(end 35.514788 -209.906616)
		(width 0.18288)
		(layer "In4.Cu")
		(net "M_C_CPU1_SB_DQS_DN<2>")
	)
	(segment
		(start 69.383656 -218.569794)
		(end 69.220842 -218.502484)
		(width 0.18288)
		(layer "In4.Cu")
		(net "M_C_CPU1_SB_DQS_DN<2>")
	)
	(segment
		(start 83.143852 -229.233476)
		(end 82.791554 -229.233476)
		(width 0.088646)
		(layer "In4.Cu")
		(net "M_C_CPU1_SB_DQS_DN<2>")
	)
	(segment
		(start 46.505876 -212.456268)
		(end 45.952918 -212.456268)
		(width 0.18288)
		(layer "In4.Cu")
		(net "M_C_CPU1_SB_DQS_DN<2>")
	)
	(segment
		(start 46.77029 -212.191854)
		(end 46.505876 -212.456268)
		(width 0.18288)
		(layer "In4.Cu")
		(net "M_C_CPU1_SB_DQS_DN<2>")
	)
	(segment
		(start 70.414642 -221.05747)
		(end 70.251828 -220.99016)
		(width 0.18288)
		(layer "In4.Cu")
		(net "M_C_CPU1_SB_DQS_DN<2>")
	)
	(segment
		(start 84.661248 -230.406702)
		(end 84.661248 -230.40721)
		(width 0.088646)
		(layer "In4.Cu")
		(net "M_C_CPU1_SB_DQS_DN<2>")
	)
	(segment
		(start 91.434412 -230.086662)
		(end 91.41841 -230.144574)
		(width 0.088646)
		(layer "In4.Cu")
		(net "M_C_CPU1_SB_DQS_DN<2>")
	)
	(segment
		(start 66.51244 -212.46973)
		(end 65.7098 -212.46973)
		(width 0.18288)
		(layer "In4.Cu")
		(net "M_C_CPU1_SB_DQS_DN<2>")
	)
	(segment
		(start 83.584288 -229.673912)
		(end 83.143852 -229.233476)
		(width 0.088646)
		(layer "In4.Cu")
		(net "M_C_CPU1_SB_DQS_DN<2>")
	)
	(segment
		(start 64.91224 -212.46973)
		(end 64.169798 -212.46973)
		(width 0.18288)
		(layer "In4.Cu")
		(net "M_C_CPU1_SB_DQS_DN<2>")
	)
	(segment
		(start 82.791554 -229.233476)
		(end 82.731864 -229.173786)
		(width 0.088646)
		(layer "In4.Cu")
		(net "M_C_CPU1_SB_DQS_DN<2>")
	)
	(segment
		(start 70.55739 -221.727268)
		(end 70.6247 -221.564708)
		(width 0.18288)
		(layer "In4.Cu")
		(net "M_C_CPU1_SB_DQS_DN<2>")
	)
	(segment
		(start 82.731864 -229.173786)
		(end 82.708496 -229.173786)
		(width 0.088646)
		(layer "In4.Cu")
		(net "M_C_CPU1_SB_DQS_DN<2>")
	)
	(segment
		(start 88.803988 -230.410258)
		(end 88.802464 -230.41102)
		(width 0.088646)
		(layer "In4.Cu")
		(net "M_C_CPU1_SB_DQS_DN<2>")
	)
	(segment
		(start 68.562982 -216.589356)
		(end 68.352924 -216.082118)
		(width 0.18288)
		(layer "In4.Cu")
		(net "M_C_CPU1_SB_DQS_DN<2>")
	)
	(segment
		(start 65.0367 -212.34527)
		(end 64.91224 -212.46973)
		(width 0.18288)
		(layer "In4.Cu")
		(net "M_C_CPU1_SB_DQS_DN<2>")
	)
	(segment
		(start 59.737752 -211.584032)
		(end 59.004708 -210.850988)
		(width 0.18288)
		(layer "In4.Cu")
		(net "M_C_CPU1_SB_DQS_DN<2>")
	)
	(segment
		(start 69.593714 -219.077032)
		(end 69.383656 -218.569794)
		(width 0.18288)
		(layer "In4.Cu")
		(net "M_C_CPU1_SB_DQS_DN<2>")
	)
	(arc
		(start 89.74201 -230.41102)
		(mid 89.554812 -230.461163)
		(end 89.367614 -230.41102)
		(width 0.088646)
		(layer "In4.Cu")
		(net "M_C_CPU1_SB_DQS_DN<2>")
	)
	(arc
		(start 87.86241 -230.41102)
		(mid 87.675212 -230.461163)
		(end 87.488014 -230.41102)
		(width 0.088646)
		(layer "In4.Cu")
		(net "M_C_CPU1_SB_DQS_DN<2>")
	)
	(arc
		(start 86.533482 -230.402384)
		(mid 86.257007 -230.335064)
		(end 85.98281 -230.41102)
		(width 0.088646)
		(layer "In4.Cu")
		(net "M_C_CPU1_SB_DQS_DN<2>")
	)
	(arc
		(start 85.593682 -230.402384)
		(mid 85.317207 -230.335064)
		(end 85.04301 -230.41102)
		(width 0.088646)
		(layer "In4.Cu")
		(net "M_C_CPU1_SB_DQS_DN<2>")
	)
	(arc
		(start 86.92261 -230.41102)
		(mid 86.735412 -230.461163)
		(end 86.548214 -230.41102)
		(width 0.088646)
		(layer "In4.Cu")
		(net "M_C_CPU1_SB_DQS_DN<2>")
	)
	(arc
		(start 89.367614 -230.41102)
		(mid 89.088411 -230.33538)
		(end 88.808306 -230.407718)
		(width 0.088646)
		(layer "In4.Cu")
		(net "M_C_CPU1_SB_DQS_DN<2>")
	)
	(arc
		(start 88.798654 -230.413306)
		(mid 88.612935 -230.461258)
		(end 88.427814 -230.41102)
		(width 0.088646)
		(layer "In4.Cu")
		(net "M_C_CPU1_SB_DQS_DN<2>")
	)
	(arc
		(start 87.473282 -230.402384)
		(mid 87.196807 -230.335064)
		(end 86.92261 -230.41102)
		(width 0.088646)
		(layer "In4.Cu")
		(net "M_C_CPU1_SB_DQS_DN<2>")
	)
	(arc
		(start 85.98281 -230.41102)
		(mid 85.795612 -230.461163)
		(end 85.608414 -230.41102)
		(width 0.088646)
		(layer "In4.Cu")
		(net "M_C_CPU1_SB_DQS_DN<2>")
	)
	(arc
		(start 90.682064 -230.41102)
		(mid 90.494866 -230.461163)
		(end 90.307668 -230.41102)
		(width 0.088646)
		(layer "In4.Cu")
		(net "M_C_CPU1_SB_DQS_DN<2>")
	)
	(arc
		(start 85.04301 -230.41102)
		(mid 84.855812 -230.461163)
		(end 84.668614 -230.41102)
		(width 0.088646)
		(layer "In4.Cu")
		(net "M_C_CPU1_SB_DQS_DN<2>")
	)
	(arc
		(start 88.413082 -230.402384)
		(mid 88.136607 -230.335064)
		(end 87.86241 -230.41102)
		(width 0.088646)
		(layer "In4.Cu")
		(net "M_C_CPU1_SB_DQS_DN<2>")
	)
	(arc
		(start 84.387436 -230.335328)
		(mid 84.172162 -230.292072)
		(end 83.989672 -230.169974)
		(width 0.088646)
		(layer "In4.Cu")
		(net "M_C_CPU1_SB_DQS_DN<2>")
	)
	(arc
		(start 91.41841 -230.144574)
		(mid 91.387365 -230.197835)
		(end 91.333828 -230.228394)
		(width 0.088646)
		(layer "In4.Cu")
		(net "M_C_CPU1_SB_DQS_DN<2>")
	)
	(arc
		(start 90.297254 -230.404924)
		(mid 90.018822 -230.335078)
		(end 89.74201 -230.41102)
		(width 0.088646)
		(layer "In4.Cu")
		(net "M_C_CPU1_SB_DQS_DN<2>")
	)
	(arc
		(start 84.661248 -230.40721)
		(mid 84.52892 -230.353821)
		(end 84.387436 -230.335328)
		(width 0.088646)
		(layer "In4.Cu")
		(net "M_C_CPU1_SB_DQS_DN<2>")
	)
	(segment
		(start 30.225238 -218.566746)
		(end 30.771846 -218.566746)
		(width 0.20066)
		(layer "F.Cu")
		(net "M_C_CPU1_SB_DQS_DN<1>")
	)
	(segment
		(start 26.20391 -218.98102)
		(end 26.204672 -218.98102)
		(width 0.101854)
		(layer "F.Cu")
		(net "M_C_CPU1_SB_DQS_DN<1>")
	)
	(segment
		(start 29.964126 -218.827858)
		(end 30.225238 -218.566746)
		(width 0.20066)
		(layer "F.Cu")
		(net "M_C_CPU1_SB_DQS_DN<1>")
	)
	(segment
		(start 26.204672 -218.98102)
		(end 26.21534 -218.991688)
		(width 0.101854)
		(layer "F.Cu")
		(net "M_C_CPU1_SB_DQS_DN<1>")
	)
	(segment
		(start 24.037798 -218.827858)
		(end 24.55164 -218.827858)
		(width 0.20066)
		(layer "F.Cu")
		(net "M_C_CPU1_SB_DQS_DN<1>")
	)
	(segment
		(start 24.55164 -218.827858)
		(end 25.187656 -219.253054)
		(width 0.20066)
		(layer "F.Cu")
		(net "M_C_CPU1_SB_DQS_DN<1>")
	)
	(segment
		(start 29.557472 -218.827858)
		(end 29.964126 -218.827858)
		(width 0.20066)
		(layer "F.Cu")
		(net "M_C_CPU1_SB_DQS_DN<1>")
	)
	(segment
		(start 26.21534 -218.991688)
		(end 28.529026 -218.991688)
		(width 0.1016)
		(layer "F.Cu")
		(net "M_C_CPU1_SB_DQS_DN<1>")
	)
	(segment
		(start 28.945586 -219.253054)
		(end 29.132276 -219.253054)
		(width 0.20066)
		(layer "F.Cu")
		(net "M_C_CPU1_SB_DQS_DN<1>")
	)
	(segment
		(start 23.228046 -218.566746)
		(end 23.776686 -218.566746)
		(width 0.20066)
		(layer "F.Cu")
		(net "M_C_CPU1_SB_DQS_DN<1>")
	)
	(segment
		(start 28.68422 -218.991688)
		(end 28.945586 -219.253054)
		(width 0.20066)
		(layer "F.Cu")
		(net "M_C_CPU1_SB_DQS_DN<1>")
	)
	(segment
		(start 28.529026 -218.991688)
		(end 28.68422 -218.991688)
		(width 0.20066)
		(layer "F.Cu")
		(net "M_C_CPU1_SB_DQS_DN<1>")
	)
	(segment
		(start 25.72766 -219.253054)
		(end 25.999694 -218.98102)
		(width 0.20066)
		(layer "F.Cu")
		(net "M_C_CPU1_SB_DQS_DN<1>")
	)
	(segment
		(start 23.776686 -218.566746)
		(end 24.037798 -218.827858)
		(width 0.20066)
		(layer "F.Cu")
		(net "M_C_CPU1_SB_DQS_DN<1>")
	)
	(segment
		(start 94.723712 -237.947454)
		(end 94.723966 -237.9472)
		(width 0.20066)
		(layer "F.Cu")
		(net "M_C_CPU1_SB_DQS_DN<1>")
	)
	(segment
		(start 29.132276 -219.253054)
		(end 29.557472 -218.827858)
		(width 0.20066)
		(layer "F.Cu")
		(net "M_C_CPU1_SB_DQS_DN<1>")
	)
	(segment
		(start 31.876746 -218.566746)
		(end 30.771846 -218.566746)
		(width 0.20066)
		(layer "F.Cu")
		(net "M_C_CPU1_SB_DQS_DN<1>")
	)
	(segment
		(start 25.187656 -219.253054)
		(end 25.72766 -219.253054)
		(width 0.20066)
		(layer "F.Cu")
		(net "M_C_CPU1_SB_DQS_DN<1>")
	)
	(segment
		(start 25.999694 -218.98102)
		(end 26.20391 -218.98102)
		(width 0.20066)
		(layer "F.Cu")
		(net "M_C_CPU1_SB_DQS_DN<1>")
	)
	(segment
		(start 94.723966 -237.9472)
		(end 94.723966 -237.411514)
		(width 0.20066)
		(layer "F.Cu")
		(net "M_C_CPU1_SB_DQS_DN<1>")
	)
	(segment
		(start 33.27654 -218.628976)
		(end 32.909002 -218.628976)
		(width 0.18288)
		(layer "In6.Cu")
		(net "M_C_CPU1_SB_DQS_DN<1>")
	)
	(segment
		(start 47.485554 -221.822772)
		(end 47.203106 -221.540324)
		(width 0.18288)
		(layer "In6.Cu")
		(net "M_C_CPU1_SB_DQS_DN<1>")
	)
	(segment
		(start 35.724338 -218.993212)
		(end 35.461194 -219.256356)
		(width 0.18288)
		(layer "In6.Cu")
		(net "M_C_CPU1_SB_DQS_DN<1>")
	)
	(segment
		(start 65.1637 -226.056952)
		(end 64.519556 -225.412554)
		(width 0.18288)
		(layer "In6.Cu")
		(net "M_C_CPU1_SB_DQS_DN<1>")
	)
	(segment
		(start 38.884352 -219.149422)
		(end 38.335712 -219.149422)
		(width 0.18288)
		(layer "In6.Cu")
		(net "M_C_CPU1_SB_DQS_DN<1>")
	)
	(segment
		(start 53.747162 -222.514922)
		(end 53.198522 -222.514922)
		(width 0.18288)
		(layer "In6.Cu")
		(net "M_C_CPU1_SB_DQS_DN<1>")
	)
	(segment
		(start 46.1137 -221.806262)
		(end 45.809662 -221.50197)
		(width 0.18288)
		(layer "In6.Cu")
		(net "M_C_CPU1_SB_DQS_DN<1>")
	)
	(segment
		(start 41.50741 -220.08211)
		(end 40.806878 -219.791788)
		(width 0.18288)
		(layer "In6.Cu")
		(net "M_C_CPU1_SB_DQS_DN<1>")
	)
	(segment
		(start 83.691476 -236.239558)
		(end 83.612482 -236.160564)
		(width 0.088646)
		(layer "In6.Cu")
		(net "M_C_CPU1_SB_DQS_DN<1>")
	)
	(segment
		(start 62.954154 -223.701102)
		(end 62.554104 -222.952564)
		(width 0.18288)
		(layer "In6.Cu")
		(net "M_C_CPU1_SB_DQS_DN<1>")
	)
	(segment
		(start 48.18507 -221.822772)
		(end 47.485554 -221.822772)
		(width 0.18288)
		(layer "In6.Cu")
		(net "M_C_CPU1_SB_DQS_DN<1>")
	)
	(segment
		(start 41.998646 -220.397578)
		(end 41.822624 -220.397578)
		(width 0.18288)
		(layer "In6.Cu")
		(net "M_C_CPU1_SB_DQS_DN<1>")
	)
	(segment
		(start 94.22511 -237.59033)
		(end 93.971872 -237.736126)
		(width 0.088646)
		(layer "In6.Cu")
		(net "M_C_CPU1_SB_DQS_DN<1>")
	)
	(segment
		(start 51.572668 -222.639382)
		(end 51.322224 -222.388938)
		(width 0.18288)
		(layer "In6.Cu")
		(net "M_C_CPU1_SB_DQS_DN<1>")
	)
	(segment
		(start 56.560974 -222.063818)
		(end 56.436514 -221.939358)
		(width 0.18288)
		(layer "In6.Cu")
		(net "M_C_CPU1_SB_DQS_DN<1>")
	)
	(segment
		(start 56.436514 -221.939358)
		(end 55.887874 -221.939358)
		(width 0.18288)
		(layer "In6.Cu")
		(net "M_C_CPU1_SB_DQS_DN<1>")
	)
	(segment
		(start 86.463378 -237.73003)
		(end 86.452964 -237.736126)
		(width 0.088646)
		(layer "In6.Cu")
		(net "M_C_CPU1_SB_DQS_DN<1>")
	)
	(segment
		(start 40.739568 -219.628974)
		(end 40.232584 -219.418916)
		(width 0.18288)
		(layer "In6.Cu")
		(net "M_C_CPU1_SB_DQS_DN<1>")
	)
	(segment
		(start 94.723966 -237.411514)
		(end 94.692216 -237.527338)
		(width 0.088646)
		(layer "In6.Cu")
		(net "M_C_CPU1_SB_DQS_DN<1>")
	)
	(segment
		(start 50.805842 -222.388938)
		(end 50.558954 -222.635826)
		(width 0.18288)
		(layer "In6.Cu")
		(net "M_C_CPU1_SB_DQS_DN<1>")
	)
	(segment
		(start 90.226896 -237.72749)
		(end 90.212164 -237.736126)
		(width 0.088646)
		(layer "In6.Cu")
		(net "M_C_CPU1_SB_DQS_DN<1>")
	)
	(segment
		(start 43.271694 -221.556072)
		(end 42.774616 -221.349824)
		(width 0.18288)
		(layer "In6.Cu")
		(net "M_C_CPU1_SB_DQS_DN<1>")
	)
	(segment
		(start 36.488878 -219.273882)
		(end 36.208208 -218.993212)
		(width 0.18288)
		(layer "In6.Cu")
		(net "M_C_CPU1_SB_DQS_DN<1>")
	)
	(segment
		(start 50.558954 -222.635826)
		(end 50.25644 -222.635826)
		(width 0.18288)
		(layer "In6.Cu")
		(net "M_C_CPU1_SB_DQS_DN<1>")
	)
	(segment
		(start 48.98263 -221.822772)
		(end 48.85817 -221.698312)
		(width 0.18288)
		(layer "In6.Cu")
		(net "M_C_CPU1_SB_DQS_DN<1>")
	)
	(segment
		(start 82.918554 -235.265722)
		(end 82.858864 -235.206032)
		(width 0.088646)
		(layer "In6.Cu")
		(net "M_C_CPU1_SB_DQS_DN<1>")
	)
	(segment
		(start 53.074062 -222.639382)
		(end 51.572668 -222.639382)
		(width 0.18288)
		(layer "In6.Cu")
		(net "M_C_CPU1_SB_DQS_DN<1>")
	)
	(segment
		(start 83.612482 -236.160564)
		(end 83.612482 -235.703618)
		(width 0.088646)
		(layer "In6.Cu")
		(net "M_C_CPU1_SB_DQS_DN<1>")
	)
	(segment
		(start 92.09151 -237.735872)
		(end 92.09151 -237.736126)
		(width 0.088646)
		(layer "In6.Cu")
		(net "M_C_CPU1_SB_DQS_DN<1>")
	)
	(segment
		(start 63.381382 -224.23628)
		(end 63.122556 -223.752156)
		(width 0.18288)
		(layer "In6.Cu")
		(net "M_C_CPU1_SB_DQS_DN<1>")
	)
	(segment
		(start 43.741594 -221.556072)
		(end 43.271694 -221.556072)
		(width 0.18288)
		(layer "In6.Cu")
		(net "M_C_CPU1_SB_DQS_DN<1>")
	)
	(segment
		(start 93.597222 -237.735872)
		(end 93.596968 -237.735872)
		(width 0.088646)
		(layer "In6.Cu")
		(net "M_C_CPU1_SB_DQS_DN<1>")
	)
	(segment
		(start 57.907174 -222.063818)
		(end 57.782714 -221.939358)
		(width 0.18288)
		(layer "In6.Cu")
		(net "M_C_CPU1_SB_DQS_DN<1>")
	)
	(segment
		(start 38.335712 -219.149422)
		(end 38.211252 -219.273882)
		(width 0.18288)
		(layer "In6.Cu")
		(net "M_C_CPU1_SB_DQS_DN<1>")
	)
	(segment
		(start 49.443894 -221.822772)
		(end 48.98263 -221.822772)
		(width 0.18288)
		(layer "In6.Cu")
		(net "M_C_CPU1_SB_DQS_DN<1>")
	)
	(segment
		(start 63.588646 -224.888552)
		(end 63.330074 -224.404682)
		(width 0.18288)
		(layer "In6.Cu")
		(net "M_C_CPU1_SB_DQS_DN<1>")
	)
	(segment
		(start 84.076032 -236.934756)
		(end 84.038694 -236.934756)
		(width 0.088646)
		(layer "In6.Cu")
		(net "M_C_CPU1_SB_DQS_DN<1>")
	)
	(segment
		(start 36.208208 -218.993212)
		(end 35.724338 -218.993212)
		(width 0.18288)
		(layer "In6.Cu")
		(net "M_C_CPU1_SB_DQS_DN<1>")
	)
	(segment
		(start 67.476116 -228.120194)
		(end 67.476116 -226.499928)
		(width 0.18288)
		(layer "In6.Cu")
		(net "M_C_CPU1_SB_DQS_DN<1>")
	)
	(segment
		(start 88.347296 -237.727236)
		(end 88.332564 -237.735872)
		(width 0.088646)
		(layer "In6.Cu")
		(net "M_C_CPU1_SB_DQS_DN<1>")
	)
	(segment
		(start 57.109614 -222.063818)
		(end 56.560974 -222.063818)
		(width 0.18288)
		(layer "In6.Cu")
		(net "M_C_CPU1_SB_DQS_DN<1>")
	)
	(segment
		(start 40.232584 -219.418916)
		(end 40.070024 -219.486226)
		(width 0.18288)
		(layer "In6.Cu")
		(net "M_C_CPU1_SB_DQS_DN<1>")
	)
	(segment
		(start 32.14116 -218.83116)
		(end 31.876746 -218.566746)
		(width 0.18288)
		(layer "In6.Cu")
		(net "M_C_CPU1_SB_DQS_DN<1>")
	)
	(segment
		(start 83.174586 -235.265722)
		(end 82.918554 -235.265722)
		(width 0.088646)
		(layer "In6.Cu")
		(net "M_C_CPU1_SB_DQS_DN<1>")
	)
	(segment
		(start 32.42056 -218.83116)
		(end 32.14116 -218.83116)
		(width 0.18288)
		(layer "In6.Cu")
		(net "M_C_CPU1_SB_DQS_DN<1>")
	)
	(segment
		(start 55.763414 -222.063818)
		(end 55.214774 -222.063818)
		(width 0.18288)
		(layer "In6.Cu")
		(net "M_C_CPU1_SB_DQS_DN<1>")
	)
	(segment
		(start 91.717114 -237.736126)
		(end 91.7067 -237.73003)
		(width 0.088646)
		(layer "In6.Cu")
		(net "M_C_CPU1_SB_DQS_DN<1>")
	)
	(segment
		(start 40.806878 -219.791788)
		(end 40.739568 -219.628974)
		(width 0.18288)
		(layer "In6.Cu")
		(net "M_C_CPU1_SB_DQS_DN<1>")
	)
	(segment
		(start 65.678304 -226.056952)
		(end 65.1637 -226.056952)
		(width 0.18288)
		(layer "In6.Cu")
		(net "M_C_CPU1_SB_DQS_DN<1>")
	)
	(segment
		(start 89.837768 -237.736126)
		(end 89.837768 -237.735872)
		(width 0.088646)
		(layer "In6.Cu")
		(net "M_C_CPU1_SB_DQS_DN<1>")
	)
	(segment
		(start 57.234074 -221.939358)
		(end 57.109614 -222.063818)
		(width 0.18288)
		(layer "In6.Cu")
		(net "M_C_CPU1_SB_DQS_DN<1>")
	)
	(segment
		(start 45.809662 -221.50197)
		(end 45.127926 -221.219776)
		(width 0.18288)
		(layer "In6.Cu")
		(net "M_C_CPU1_SB_DQS_DN<1>")
	)
	(segment
		(start 93.046296 -237.727236)
		(end 93.031564 -237.735872)
		(width 0.088646)
		(layer "In6.Cu")
		(net "M_C_CPU1_SB_DQS_DN<1>")
	)
	(segment
		(start 66.59372 -226.046538)
		(end 66.340736 -225.793554)
		(width 0.18288)
		(layer "In6.Cu")
		(net "M_C_CPU1_SB_DQS_DN<1>")
	)
	(segment
		(start 57.782714 -221.939358)
		(end 57.234074 -221.939358)
		(width 0.18288)
		(layer "In6.Cu")
		(net "M_C_CPU1_SB_DQS_DN<1>")
	)
	(segment
		(start 82.858864 -235.206032)
		(end 82.835496 -235.206032)
		(width 0.088646)
		(layer "In6.Cu")
		(net "M_C_CPU1_SB_DQS_DN<1>")
	)
	(segment
		(start 83.612482 -235.703618)
		(end 83.174586 -235.265722)
		(width 0.088646)
		(layer "In6.Cu")
		(net "M_C_CPU1_SB_DQS_DN<1>")
	)
	(segment
		(start 93.971872 -237.736126)
		(end 93.971618 -237.735872)
		(width 0.088646)
		(layer "In6.Cu")
		(net "M_C_CPU1_SB_DQS_DN<1>")
	)
	(segment
		(start 82.835496 -235.206032)
		(end 74.561954 -235.206032)
		(width 0.18288)
		(layer "In6.Cu")
		(net "M_C_CPU1_SB_DQS_DN<1>")
	)
	(segment
		(start 42.386758 -220.961966)
		(end 42.387012 -220.785944)
		(width 0.18288)
		(layer "In6.Cu")
		(net "M_C_CPU1_SB_DQS_DN<1>")
	)
	(segment
		(start 87.4014 -237.730792)
		(end 87.39251 -237.736126)
		(width 0.088646)
		(layer "In6.Cu")
		(net "M_C_CPU1_SB_DQS_DN<1>")
	)
	(segment
		(start 41.822624 -220.397578)
		(end 41.50741 -220.08211)
		(width 0.18288)
		(layer "In6.Cu")
		(net "M_C_CPU1_SB_DQS_DN<1>")
	)
	(segment
		(start 48.85817 -221.698312)
		(end 48.30953 -221.698312)
		(width 0.18288)
		(layer "In6.Cu")
		(net "M_C_CPU1_SB_DQS_DN<1>")
	)
	(segment
		(start 47.203106 -221.540324)
		(end 46.724824 -221.540324)
		(width 0.18288)
		(layer "In6.Cu")
		(net "M_C_CPU1_SB_DQS_DN<1>")
	)
	(segment
		(start 63.330074 -224.404682)
		(end 63.381382 -224.23628)
		(width 0.18288)
		(layer "In6.Cu")
		(net "M_C_CPU1_SB_DQS_DN<1>")
	)
	(segment
		(start 62.554104 -222.952564)
		(end 61.859414 -222.66529)
		(width 0.18288)
		(layer "In6.Cu")
		(net "M_C_CPU1_SB_DQS_DN<1>")
	)
	(segment
		(start 33.401 -218.504516)
		(end 33.27654 -218.628976)
		(width 0.18288)
		(layer "In6.Cu")
		(net "M_C_CPU1_SB_DQS_DN<1>")
	)
	(segment
		(start 53.871622 -222.639382)
		(end 53.747162 -222.514922)
		(width 0.18288)
		(layer "In6.Cu")
		(net "M_C_CPU1_SB_DQS_DN<1>")
	)
	(segment
		(start 39.557452 -219.273882)
		(end 39.008812 -219.273882)
		(width 0.18288)
		(layer "In6.Cu")
		(net "M_C_CPU1_SB_DQS_DN<1>")
	)
	(segment
		(start 34.514028 -218.628976)
		(end 34.0741 -218.628976)
		(width 0.18288)
		(layer "In6.Cu")
		(net "M_C_CPU1_SB_DQS_DN<1>")
	)
	(segment
		(start 45.127926 -221.219776)
		(end 44.553632 -221.219776)
		(width 0.18288)
		(layer "In6.Cu")
		(net "M_C_CPU1_SB_DQS_DN<1>")
	)
	(segment
		(start 55.214774 -222.063818)
		(end 54.63921 -222.639382)
		(width 0.18288)
		(layer "In6.Cu")
		(net "M_C_CPU1_SB_DQS_DN<1>")
	)
	(segment
		(start 32.909002 -218.628976)
		(end 32.42056 -218.83116)
		(width 0.18288)
		(layer "In6.Cu")
		(net "M_C_CPU1_SB_DQS_DN<1>")
	)
	(segment
		(start 63.824866 -225.124772)
		(end 63.588646 -224.888552)
		(width 0.18288)
		(layer "In6.Cu")
		(net "M_C_CPU1_SB_DQS_DN<1>")
	)
	(segment
		(start 46.458886 -221.806262)
		(end 46.1137 -221.806262)
		(width 0.18288)
		(layer "In6.Cu")
		(net "M_C_CPU1_SB_DQS_DN<1>")
	)
	(segment
		(start 67.022726 -226.046538)
		(end 66.59372 -226.046538)
		(width 0.18288)
		(layer "In6.Cu")
		(net "M_C_CPU1_SB_DQS_DN<1>")
	)
	(segment
		(start 58.750962 -222.063818)
		(end 57.907174 -222.063818)
		(width 0.18288)
		(layer "In6.Cu")
		(net "M_C_CPU1_SB_DQS_DN<1>")
	)
	(segment
		(start 38.211252 -219.273882)
		(end 36.488878 -219.273882)
		(width 0.18288)
		(layer "In6.Cu")
		(net "M_C_CPU1_SB_DQS_DN<1>")
	)
	(segment
		(start 85.057996 -236.913674)
		(end 85.043264 -236.92231)
		(width 0.088646)
		(layer "In6.Cu")
		(net "M_C_CPU1_SB_DQS_DN<1>")
	)
	(segment
		(start 39.008812 -219.273882)
		(end 38.884352 -219.149422)
		(width 0.18288)
		(layer "In6.Cu")
		(net "M_C_CPU1_SB_DQS_DN<1>")
	)
	(segment
		(start 85.624162 -236.931708)
		(end 85.608668 -236.92231)
		(width 0.088646)
		(layer "In6.Cu")
		(net "M_C_CPU1_SB_DQS_DN<1>")
	)
	(segment
		(start 51.322224 -222.388938)
		(end 50.805842 -222.388938)
		(width 0.18288)
		(layer "In6.Cu")
		(net "M_C_CPU1_SB_DQS_DN<1>")
	)
	(segment
		(start 46.724824 -221.540324)
		(end 46.458886 -221.806262)
		(width 0.18288)
		(layer "In6.Cu")
		(net "M_C_CPU1_SB_DQS_DN<1>")
	)
	(segment
		(start 74.561954 -235.206032)
		(end 67.476116 -228.120194)
		(width 0.18288)
		(layer "In6.Cu")
		(net "M_C_CPU1_SB_DQS_DN<1>")
	)
	(segment
		(start 64.519556 -225.412554)
		(end 63.824866 -225.124772)
		(width 0.18288)
		(layer "In6.Cu")
		(net "M_C_CPU1_SB_DQS_DN<1>")
	)
	(segment
		(start 84.114132 -236.916214)
		(end 84.114386 -236.916468)
		(width 0.088646)
		(layer "In6.Cu")
		(net "M_C_CPU1_SB_DQS_DN<1>")
	)
	(segment
		(start 33.94964 -218.504516)
		(end 33.401 -218.504516)
		(width 0.18288)
		(layer "In6.Cu")
		(net "M_C_CPU1_SB_DQS_DN<1>")
	)
	(segment
		(start 53.198522 -222.514922)
		(end 53.074062 -222.639382)
		(width 0.18288)
		(layer "In6.Cu")
		(net "M_C_CPU1_SB_DQS_DN<1>")
	)
	(segment
		(start 61.859414 -222.66529)
		(end 60.202826 -222.66529)
		(width 0.18288)
		(layer "In6.Cu")
		(net "M_C_CPU1_SB_DQS_DN<1>")
	)
	(segment
		(start 89.287096 -237.727236)
		(end 89.272364 -237.735872)
		(width 0.088646)
		(layer "In6.Cu")
		(net "M_C_CPU1_SB_DQS_DN<1>")
	)
	(segment
		(start 63.122556 -223.752156)
		(end 62.954154 -223.701102)
		(width 0.18288)
		(layer "In6.Cu")
		(net "M_C_CPU1_SB_DQS_DN<1>")
	)
	(segment
		(start 54.63921 -222.639382)
		(end 53.871622 -222.639382)
		(width 0.18288)
		(layer "In6.Cu")
		(net "M_C_CPU1_SB_DQS_DN<1>")
	)
	(segment
		(start 94.498668 -237.59033)
		(end 94.22511 -237.59033)
		(width 0.088646)
		(layer "In6.Cu")
		(net "M_C_CPU1_SB_DQS_DN<1>")
	)
	(segment
		(start 65.941702 -225.793554)
		(end 65.678304 -226.056952)
		(width 0.18288)
		(layer "In6.Cu")
		(net "M_C_CPU1_SB_DQS_DN<1>")
	)
	(segment
		(start 42.774616 -221.349824)
		(end 42.386758 -220.961966)
		(width 0.18288)
		(layer "In6.Cu")
		(net "M_C_CPU1_SB_DQS_DN<1>")
	)
	(segment
		(start 44.553632 -221.219776)
		(end 43.741594 -221.556072)
		(width 0.18288)
		(layer "In6.Cu")
		(net "M_C_CPU1_SB_DQS_DN<1>")
	)
	(segment
		(start 55.887874 -221.939358)
		(end 55.763414 -222.063818)
		(width 0.18288)
		(layer "In6.Cu")
		(net "M_C_CPU1_SB_DQS_DN<1>")
	)
	(segment
		(start 50.25644 -222.635826)
		(end 49.443894 -221.822772)
		(width 0.18288)
		(layer "In6.Cu")
		(net "M_C_CPU1_SB_DQS_DN<1>")
	)
	(segment
		(start 40.070024 -219.486226)
		(end 39.557452 -219.273882)
		(width 0.18288)
		(layer "In6.Cu")
		(net "M_C_CPU1_SB_DQS_DN<1>")
	)
	(segment
		(start 48.30953 -221.698312)
		(end 48.18507 -221.822772)
		(width 0.18288)
		(layer "In6.Cu")
		(net "M_C_CPU1_SB_DQS_DN<1>")
	)
	(segment
		(start 67.476116 -226.499928)
		(end 67.022726 -226.046538)
		(width 0.18288)
		(layer "In6.Cu")
		(net "M_C_CPU1_SB_DQS_DN<1>")
	)
	(segment
		(start 60.202826 -222.66529)
		(end 58.750962 -222.063818)
		(width 0.18288)
		(layer "In6.Cu")
		(net "M_C_CPU1_SB_DQS_DN<1>")
	)
	(segment
		(start 42.387012 -220.785944)
		(end 41.998646 -220.397578)
		(width 0.18288)
		(layer "In6.Cu")
		(net "M_C_CPU1_SB_DQS_DN<1>")
	)
	(segment
		(start 84.038694 -236.934756)
		(end 83.691476 -236.587538)
		(width 0.088646)
		(layer "In6.Cu")
		(net "M_C_CPU1_SB_DQS_DN<1>")
	)
	(segment
		(start 34.0741 -218.628976)
		(end 33.94964 -218.504516)
		(width 0.18288)
		(layer "In6.Cu")
		(net "M_C_CPU1_SB_DQS_DN<1>")
	)
	(segment
		(start 83.691476 -236.587538)
		(end 83.691476 -236.239558)
		(width 0.088646)
		(layer "In6.Cu")
		(net "M_C_CPU1_SB_DQS_DN<1>")
	)
	(segment
		(start 66.340736 -225.793554)
		(end 65.941702 -225.793554)
		(width 0.18288)
		(layer "In6.Cu")
		(net "M_C_CPU1_SB_DQS_DN<1>")
	)
	(segment
		(start 35.461194 -219.256356)
		(end 35.141408 -219.256356)
		(width 0.18288)
		(layer "In6.Cu")
		(net "M_C_CPU1_SB_DQS_DN<1>")
	)
	(segment
		(start 92.101924 -237.729776)
		(end 92.09151 -237.735872)
		(width 0.088646)
		(layer "In6.Cu")
		(net "M_C_CPU1_SB_DQS_DN<1>")
	)
	(segment
		(start 94.692216 -237.527338)
		(end 94.653354 -237.549436)
		(width 0.088646)
		(layer "In6.Cu")
		(net "M_C_CPU1_SB_DQS_DN<1>")
	)
	(segment
		(start 35.141408 -219.256356)
		(end 34.514028 -218.628976)
		(width 0.18288)
		(layer "In6.Cu")
		(net "M_C_CPU1_SB_DQS_DN<1>")
	)
	(arc
		(start 91.7067 -237.73003)
		(mid 91.428522 -237.660307)
		(end 91.151964 -237.736126)
		(width 0.088646)
		(layer "In6.Cu")
		(net "M_C_CPU1_SB_DQS_DN<1>")
	)
	(arc
		(start 89.272364 -237.735872)
		(mid 89.085166 -237.786015)
		(end 88.897968 -237.735872)
		(width 0.088646)
		(layer "In6.Cu")
		(net "M_C_CPU1_SB_DQS_DN<1>")
	)
	(arc
		(start 93.596968 -237.735872)
		(mid 93.322739 -237.659947)
		(end 93.046296 -237.727236)
		(width 0.088646)
		(layer "In6.Cu")
		(net "M_C_CPU1_SB_DQS_DN<1>")
	)
	(arc
		(start 88.332564 -237.735872)
		(mid 88.145366 -237.786015)
		(end 87.958168 -237.735872)
		(width 0.088646)
		(layer "In6.Cu")
		(net "M_C_CPU1_SB_DQS_DN<1>")
	)
	(arc
		(start 87.958168 -237.735872)
		(mid 87.680442 -237.660027)
		(end 87.4014 -237.730792)
		(width 0.088646)
		(layer "In6.Cu")
		(net "M_C_CPU1_SB_DQS_DN<1>")
	)
	(arc
		(start 88.897968 -237.735872)
		(mid 88.623739 -237.659947)
		(end 88.347296 -237.727236)
		(width 0.088646)
		(layer "In6.Cu")
		(net "M_C_CPU1_SB_DQS_DN<1>")
	)
	(arc
		(start 94.653354 -237.549436)
		(mid 94.578669 -237.579941)
		(end 94.498668 -237.59033)
		(width 0.088646)
		(layer "In6.Cu")
		(net "M_C_CPU1_SB_DQS_DN<1>")
	)
	(arc
		(start 92.657168 -237.735872)
		(mid 92.380355 -237.660036)
		(end 92.101924 -237.729776)
		(width 0.088646)
		(layer "In6.Cu")
		(net "M_C_CPU1_SB_DQS_DN<1>")
	)
	(arc
		(start 86.452964 -237.736126)
		(mid 86.078489 -237.73608)
		(end 85.891116 -237.411768)
		(width 0.088646)
		(layer "In6.Cu")
		(net "M_C_CPU1_SB_DQS_DN<1>")
	)
	(arc
		(start 85.608668 -236.92231)
		(mid 85.334469 -236.846475)
		(end 85.057996 -236.913674)
		(width 0.088646)
		(layer "In6.Cu")
		(net "M_C_CPU1_SB_DQS_DN<1>")
	)
	(arc
		(start 92.09151 -237.736126)
		(mid 91.904312 -237.786269)
		(end 91.717114 -237.736126)
		(width 0.088646)
		(layer "In6.Cu")
		(net "M_C_CPU1_SB_DQS_DN<1>")
	)
	(arc
		(start 84.114386 -236.916468)
		(mid 84.095467 -236.926154)
		(end 84.076032 -236.934756)
		(width 0.088646)
		(layer "In6.Cu")
		(net "M_C_CPU1_SB_DQS_DN<1>")
	)
	(arc
		(start 85.891116 -237.411768)
		(mid 85.819891 -237.137118)
		(end 85.624162 -236.931708)
		(width 0.088646)
		(layer "In6.Cu")
		(net "M_C_CPU1_SB_DQS_DN<1>")
	)
	(arc
		(start 93.031564 -237.735872)
		(mid 92.844366 -237.786015)
		(end 92.657168 -237.735872)
		(width 0.088646)
		(layer "In6.Cu")
		(net "M_C_CPU1_SB_DQS_DN<1>")
	)
	(arc
		(start 84.668868 -236.92231)
		(mid 84.392309 -236.846567)
		(end 84.114132 -236.916214)
		(width 0.088646)
		(layer "In6.Cu")
		(net "M_C_CPU1_SB_DQS_DN<1>")
	)
	(arc
		(start 85.043264 -236.92231)
		(mid 84.856066 -236.972453)
		(end 84.668868 -236.92231)
		(width 0.088646)
		(layer "In6.Cu")
		(net "M_C_CPU1_SB_DQS_DN<1>")
	)
	(arc
		(start 87.39251 -237.736126)
		(mid 87.205312 -237.786269)
		(end 87.018114 -237.736126)
		(width 0.088646)
		(layer "In6.Cu")
		(net "M_C_CPU1_SB_DQS_DN<1>")
	)
	(arc
		(start 89.837768 -237.735872)
		(mid 89.563539 -237.659947)
		(end 89.287096 -237.727236)
		(width 0.088646)
		(layer "In6.Cu")
		(net "M_C_CPU1_SB_DQS_DN<1>")
	)
	(arc
		(start 90.777568 -237.736126)
		(mid 90.503369 -237.660291)
		(end 90.226896 -237.72749)
		(width 0.088646)
		(layer "In6.Cu")
		(net "M_C_CPU1_SB_DQS_DN<1>")
	)
	(arc
		(start 93.971618 -237.735872)
		(mid 93.78442 -237.786015)
		(end 93.597222 -237.735872)
		(width 0.088646)
		(layer "In6.Cu")
		(net "M_C_CPU1_SB_DQS_DN<1>")
	)
	(arc
		(start 90.212164 -237.736126)
		(mid 90.024966 -237.786269)
		(end 89.837768 -237.736126)
		(width 0.088646)
		(layer "In6.Cu")
		(net "M_C_CPU1_SB_DQS_DN<1>")
	)
	(arc
		(start 87.018114 -237.736126)
		(mid 86.741555 -237.660383)
		(end 86.463378 -237.73003)
		(width 0.088646)
		(layer "In6.Cu")
		(net "M_C_CPU1_SB_DQS_DN<1>")
	)
	(arc
		(start 91.151964 -237.736126)
		(mid 90.964766 -237.786269)
		(end 90.777568 -237.736126)
		(width 0.088646)
		(layer "In6.Cu")
		(net "M_C_CPU1_SB_DQS_DN<1>")
	)
	(segment
		(start 30.225238 -227.91674)
		(end 30.771846 -227.91674)
		(width 0.20066)
		(layer "F.Cu")
		(net "M_C_CPU1_SB_DQS_DN<0>")
	)
	(segment
		(start 23.776686 -227.91674)
		(end 24.037798 -228.177852)
		(width 0.20066)
		(layer "F.Cu")
		(net "M_C_CPU1_SB_DQS_DN<0>")
	)
	(segment
		(start 24.552656 -228.177852)
		(end 25.187656 -228.603048)
		(width 0.20066)
		(layer "F.Cu")
		(net "M_C_CPU1_SB_DQS_DN<0>")
	)
	(segment
		(start 25.187656 -228.603048)
		(end 25.72766 -228.603048)
		(width 0.20066)
		(layer "F.Cu")
		(net "M_C_CPU1_SB_DQS_DN<0>")
	)
	(segment
		(start 28.529026 -228.341682)
		(end 28.68422 -228.341682)
		(width 0.20066)
		(layer "F.Cu")
		(net "M_C_CPU1_SB_DQS_DN<0>")
	)
	(segment
		(start 29.557472 -228.177852)
		(end 29.964126 -228.177852)
		(width 0.20066)
		(layer "F.Cu")
		(net "M_C_CPU1_SB_DQS_DN<0>")
	)
	(segment
		(start 25.999694 -228.331014)
		(end 26.20391 -228.331014)
		(width 0.20066)
		(layer "F.Cu")
		(net "M_C_CPU1_SB_DQS_DN<0>")
	)
	(segment
		(start 31.876746 -227.91674)
		(end 30.771846 -227.91674)
		(width 0.20066)
		(layer "F.Cu")
		(net "M_C_CPU1_SB_DQS_DN<0>")
	)
	(segment
		(start 29.132276 -228.603048)
		(end 29.557472 -228.177852)
		(width 0.20066)
		(layer "F.Cu")
		(net "M_C_CPU1_SB_DQS_DN<0>")
	)
	(segment
		(start 26.21534 -228.341682)
		(end 28.529026 -228.341682)
		(width 0.1016)
		(layer "F.Cu")
		(net "M_C_CPU1_SB_DQS_DN<0>")
	)
	(segment
		(start 28.945586 -228.603048)
		(end 29.132276 -228.603048)
		(width 0.20066)
		(layer "F.Cu")
		(net "M_C_CPU1_SB_DQS_DN<0>")
	)
	(segment
		(start 28.68422 -228.341682)
		(end 28.945586 -228.603048)
		(width 0.20066)
		(layer "F.Cu")
		(net "M_C_CPU1_SB_DQS_DN<0>")
	)
	(segment
		(start 26.20391 -228.331014)
		(end 26.204672 -228.331014)
		(width 0.101854)
		(layer "F.Cu")
		(net "M_C_CPU1_SB_DQS_DN<0>")
	)
	(segment
		(start 29.964126 -228.177852)
		(end 30.225238 -227.91674)
		(width 0.20066)
		(layer "F.Cu")
		(net "M_C_CPU1_SB_DQS_DN<0>")
	)
	(segment
		(start 25.72766 -228.603048)
		(end 25.999694 -228.331014)
		(width 0.20066)
		(layer "F.Cu")
		(net "M_C_CPU1_SB_DQS_DN<0>")
	)
	(segment
		(start 94.723712 -242.830858)
		(end 94.723966 -242.294918)
		(width 0.20066)
		(layer "F.Cu")
		(net "M_C_CPU1_SB_DQS_DN<0>")
	)
	(segment
		(start 24.037798 -228.177852)
		(end 24.552656 -228.177852)
		(width 0.20066)
		(layer "F.Cu")
		(net "M_C_CPU1_SB_DQS_DN<0>")
	)
	(segment
		(start 26.204672 -228.331014)
		(end 26.21534 -228.341682)
		(width 0.101854)
		(layer "F.Cu")
		(net "M_C_CPU1_SB_DQS_DN<0>")
	)
	(segment
		(start 23.228046 -227.91674)
		(end 23.776686 -227.91674)
		(width 0.20066)
		(layer "F.Cu")
		(net "M_C_CPU1_SB_DQS_DN<0>")
	)
	(segment
		(start 38.487858 -229.483158)
		(end 38.099746 -229.095046)
		(width 0.18288)
		(layer "In6.Cu")
		(net "M_C_CPU1_SB_DQS_DN<0>")
	)
	(segment
		(start 89.271602 -242.619784)
		(end 89.259918 -242.626896)
		(width 0.088646)
		(layer "In6.Cu")
		(net "M_C_CPU1_SB_DQS_DN<0>")
	)
	(segment
		(start 94.692216 -242.410742)
		(end 94.653354 -242.43284)
		(width 0.088646)
		(layer "In6.Cu")
		(net "M_C_CPU1_SB_DQS_DN<0>")
	)
	(segment
		(start 52.222908 -233.712004)
		(end 51.613054 -233.712004)
		(width 0.18288)
		(layer "In6.Cu")
		(net "M_C_CPU1_SB_DQS_DN<0>")
	)
	(segment
		(start 92.091764 -242.619276)
		(end 92.091764 -242.61953)
		(width 0.088646)
		(layer "In6.Cu")
		(net "M_C_CPU1_SB_DQS_DN<0>")
	)
	(segment
		(start 65.502028 -236.845094)
		(end 64.707516 -236.050582)
		(width 0.18288)
		(layer "In6.Cu")
		(net "M_C_CPU1_SB_DQS_DN<0>")
	)
	(segment
		(start 52.347368 -233.587544)
		(end 52.222908 -233.712004)
		(width 0.18288)
		(layer "In6.Cu")
		(net "M_C_CPU1_SB_DQS_DN<0>")
	)
	(segment
		(start 60.98159 -235.315506)
		(end 60.85713 -235.439966)
		(width 0.18288)
		(layer "In6.Cu")
		(net "M_C_CPU1_SB_DQS_DN<0>")
	)
	(segment
		(start 45.268642 -232.282238)
		(end 44.88053 -231.894126)
		(width 0.18288)
		(layer "In6.Cu")
		(net "M_C_CPU1_SB_DQS_DN<0>")
	)
	(segment
		(start 58.897012 -234.441238)
		(end 58.348372 -234.441238)
		(width 0.18288)
		(layer "In6.Cu")
		(net "M_C_CPU1_SB_DQS_DN<0>")
	)
	(segment
		(start 48.20285 -232.860596)
		(end 47.483522 -232.860596)
		(width 0.18288)
		(layer "In6.Cu")
		(net "M_C_CPU1_SB_DQS_DN<0>")
	)
	(segment
		(start 45.268642 -232.45826)
		(end 45.268642 -232.282238)
		(width 0.18288)
		(layer "In6.Cu")
		(net "M_C_CPU1_SB_DQS_DN<0>")
	)
	(segment
		(start 84.00415 -242.443508)
		(end 84.00415 -241.76863)
		(width 0.088646)
		(layer "In6.Cu")
		(net "M_C_CPU1_SB_DQS_DN<0>")
	)
	(segment
		(start 93.046296 -242.61064)
		(end 93.031564 -242.619276)
		(width 0.088646)
		(layer "In6.Cu")
		(net "M_C_CPU1_SB_DQS_DN<0>")
	)
	(segment
		(start 87.018114 -242.619276)
		(end 87.0077 -242.61318)
		(width 0.088646)
		(layer "In6.Cu")
		(net "M_C_CPU1_SB_DQS_DN<0>")
	)
	(segment
		(start 43.203876 -231.121458)
		(end 42.66438 -230.897938)
		(width 0.18288)
		(layer "In6.Cu")
		(net "M_C_CPU1_SB_DQS_DN<0>")
	)
	(segment
		(start 38.875716 -230.047038)
		(end 38.487858 -229.65918)
		(width 0.18288)
		(layer "In6.Cu")
		(net "M_C_CPU1_SB_DQS_DN<0>")
	)
	(segment
		(start 34.604198 -228.181408)
		(end 33.971992 -227.919534)
		(width 0.18288)
		(layer "In6.Cu")
		(net "M_C_CPU1_SB_DQS_DN<0>")
	)
	(segment
		(start 91.726258 -242.62461)
		(end 91.717622 -242.619784)
		(width 0.088646)
		(layer "In6.Cu")
		(net "M_C_CPU1_SB_DQS_DN<0>")
	)
	(segment
		(start 90.211402 -242.619784)
		(end 90.199718 -242.626896)
		(width 0.088646)
		(layer "In6.Cu")
		(net "M_C_CPU1_SB_DQS_DN<0>")
	)
	(segment
		(start 64.707516 -236.050582)
		(end 63.67399 -236.050582)
		(width 0.18288)
		(layer "In6.Cu")
		(net "M_C_CPU1_SB_DQS_DN<0>")
	)
	(segment
		(start 33.971992 -227.919534)
		(end 33.22955 -227.919534)
		(width 0.18288)
		(layer "In6.Cu")
		(net "M_C_CPU1_SB_DQS_DN<0>")
	)
	(segment
		(start 88.331802 -242.619784)
		(end 88.323674 -242.62461)
		(width 0.088646)
		(layer "In6.Cu")
		(net "M_C_CPU1_SB_DQS_DN<0>")
	)
	(segment
		(start 71.415148 -241.126772)
		(end 67.13347 -236.845094)
		(width 0.18288)
		(layer "In6.Cu")
		(net "M_C_CPU1_SB_DQS_DN<0>")
	)
	(segment
		(start 46.71314 -232.591864)
		(end 46.458886 -232.846118)
		(width 0.18288)
		(layer "In6.Cu")
		(net "M_C_CPU1_SB_DQS_DN<0>")
	)
	(segment
		(start 67.13347 -236.845094)
		(end 65.502028 -236.845094)
		(width 0.18288)
		(layer "In6.Cu")
		(net "M_C_CPU1_SB_DQS_DN<0>")
	)
	(segment
		(start 50.841148 -233.441748)
		(end 50.586894 -233.696002)
		(width 0.18288)
		(layer "In6.Cu")
		(net "M_C_CPU1_SB_DQS_DN<0>")
	)
	(segment
		(start 86.078568 -242.619276)
		(end 86.068154 -242.61318)
		(width 0.088646)
		(layer "In6.Cu")
		(net "M_C_CPU1_SB_DQS_DN<0>")
	)
	(segment
		(start 35.499294 -228.59619)
		(end 35.01898 -228.59619)
		(width 0.18288)
		(layer "In6.Cu")
		(net "M_C_CPU1_SB_DQS_DN<0>")
	)
	(segment
		(start 43.873674 -231.264206)
		(end 43.36669 -231.054148)
		(width 0.18288)
		(layer "In6.Cu")
		(net "M_C_CPU1_SB_DQS_DN<0>")
	)
	(segment
		(start 37.43071 -228.602032)
		(end 36.515294 -228.602032)
		(width 0.18288)
		(layer "In6.Cu")
		(net "M_C_CPU1_SB_DQS_DN<0>")
	)
	(segment
		(start 61.65469 -235.439966)
		(end 61.53023 -235.315506)
		(width 0.18288)
		(layer "In6.Cu")
		(net "M_C_CPU1_SB_DQS_DN<0>")
	)
	(segment
		(start 62.20333 -235.439966)
		(end 61.65469 -235.439966)
		(width 0.18288)
		(layer "In6.Cu")
		(net "M_C_CPU1_SB_DQS_DN<0>")
	)
	(segment
		(start 36.254944 -228.341682)
		(end 35.753802 -228.341682)
		(width 0.18288)
		(layer "In6.Cu")
		(net "M_C_CPU1_SB_DQS_DN<0>")
	)
	(segment
		(start 51.342798 -233.441748)
		(end 50.841148 -233.441748)
		(width 0.18288)
		(layer "In6.Cu")
		(net "M_C_CPU1_SB_DQS_DN<0>")
	)
	(segment
		(start 83.421982 -241.186462)
		(end 83.172554 -241.186462)
		(width 0.088646)
		(layer "In6.Cu")
		(net "M_C_CPU1_SB_DQS_DN<0>")
	)
	(segment
		(start 38.099746 -229.095046)
		(end 37.923724 -229.095046)
		(width 0.18288)
		(layer "In6.Cu")
		(net "M_C_CPU1_SB_DQS_DN<0>")
	)
	(segment
		(start 56.204612 -234.441238)
		(end 55.644542 -234.441238)
		(width 0.18288)
		(layer "In6.Cu")
		(net "M_C_CPU1_SB_DQS_DN<0>")
	)
	(segment
		(start 58.223912 -234.316778)
		(end 57.675272 -234.316778)
		(width 0.18288)
		(layer "In6.Cu")
		(net "M_C_CPU1_SB_DQS_DN<0>")
	)
	(segment
		(start 56.329072 -234.316778)
		(end 56.204612 -234.441238)
		(width 0.18288)
		(layer "In6.Cu")
		(net "M_C_CPU1_SB_DQS_DN<0>")
	)
	(segment
		(start 50.586894 -233.696002)
		(end 50.27168 -233.696002)
		(width 0.18288)
		(layer "In6.Cu")
		(net "M_C_CPU1_SB_DQS_DN<0>")
	)
	(segment
		(start 35.01898 -228.59619)
		(end 34.604198 -228.181408)
		(width 0.18288)
		(layer "In6.Cu")
		(net "M_C_CPU1_SB_DQS_DN<0>")
	)
	(segment
		(start 58.348372 -234.441238)
		(end 58.223912 -234.316778)
		(width 0.18288)
		(layer "In6.Cu")
		(net "M_C_CPU1_SB_DQS_DN<0>")
	)
	(segment
		(start 35.753802 -228.341682)
		(end 35.499294 -228.59619)
		(width 0.18288)
		(layer "In6.Cu")
		(net "M_C_CPU1_SB_DQS_DN<0>")
	)
	(segment
		(start 36.515294 -228.602032)
		(end 36.254944 -228.341682)
		(width 0.18288)
		(layer "In6.Cu")
		(net "M_C_CPU1_SB_DQS_DN<0>")
	)
	(segment
		(start 43.940984 -231.42702)
		(end 43.873674 -231.264206)
		(width 0.18288)
		(layer "In6.Cu")
		(net "M_C_CPU1_SB_DQS_DN<0>")
	)
	(segment
		(start 53.569108 -233.712004)
		(end 53.020468 -233.712004)
		(width 0.18288)
		(layer "In6.Cu")
		(net "M_C_CPU1_SB_DQS_DN<0>")
	)
	(segment
		(start 93.971872 -242.61953)
		(end 93.971618 -242.619276)
		(width 0.088646)
		(layer "In6.Cu")
		(net "M_C_CPU1_SB_DQS_DN<0>")
	)
	(segment
		(start 84.00415 -241.76863)
		(end 83.421982 -241.186462)
		(width 0.088646)
		(layer "In6.Cu")
		(net "M_C_CPU1_SB_DQS_DN<0>")
	)
	(segment
		(start 33.22955 -227.919534)
		(end 32.611822 -228.175312)
		(width 0.18288)
		(layer "In6.Cu")
		(net "M_C_CPU1_SB_DQS_DN<0>")
	)
	(segment
		(start 57.550812 -234.441238)
		(end 57.002172 -234.441238)
		(width 0.18288)
		(layer "In6.Cu")
		(net "M_C_CPU1_SB_DQS_DN<0>")
	)
	(segment
		(start 46.458886 -232.846118)
		(end 45.6565 -232.846118)
		(width 0.18288)
		(layer "In6.Cu")
		(net "M_C_CPU1_SB_DQS_DN<0>")
	)
	(segment
		(start 94.723966 -242.294918)
		(end 94.692216 -242.410742)
		(width 0.088646)
		(layer "In6.Cu")
		(net "M_C_CPU1_SB_DQS_DN<0>")
	)
	(segment
		(start 48.32731 -232.736136)
		(end 48.20285 -232.860596)
		(width 0.18288)
		(layer "In6.Cu")
		(net "M_C_CPU1_SB_DQS_DN<0>")
	)
	(segment
		(start 40.092376 -230.047038)
		(end 38.875716 -230.047038)
		(width 0.18288)
		(layer "In6.Cu")
		(net "M_C_CPU1_SB_DQS_DN<0>")
	)
	(segment
		(start 87.957914 -242.61953)
		(end 87.958422 -242.619276)
		(width 0.088646)
		(layer "In6.Cu")
		(net "M_C_CPU1_SB_DQS_DN<0>")
	)
	(segment
		(start 93.597222 -242.619276)
		(end 93.596968 -242.619276)
		(width 0.088646)
		(layer "In6.Cu")
		(net "M_C_CPU1_SB_DQS_DN<0>")
	)
	(segment
		(start 57.002172 -234.441238)
		(end 56.877712 -234.316778)
		(width 0.18288)
		(layer "In6.Cu")
		(net "M_C_CPU1_SB_DQS_DN<0>")
	)
	(segment
		(start 61.53023 -235.315506)
		(end 60.98159 -235.315506)
		(width 0.18288)
		(layer "In6.Cu")
		(net "M_C_CPU1_SB_DQS_DN<0>")
	)
	(segment
		(start 53.693568 -233.587544)
		(end 53.569108 -233.712004)
		(width 0.18288)
		(layer "In6.Cu")
		(net "M_C_CPU1_SB_DQS_DN<0>")
	)
	(segment
		(start 83.112864 -241.126772)
		(end 83.089496 -241.126772)
		(width 0.088646)
		(layer "In6.Cu")
		(net "M_C_CPU1_SB_DQS_DN<0>")
	)
	(segment
		(start 84.120736 -242.560094)
		(end 84.00415 -242.443508)
		(width 0.088646)
		(layer "In6.Cu")
		(net "M_C_CPU1_SB_DQS_DN<0>")
	)
	(segment
		(start 45.6565 -232.846118)
		(end 45.268642 -232.45826)
		(width 0.18288)
		(layer "In6.Cu")
		(net "M_C_CPU1_SB_DQS_DN<0>")
	)
	(segment
		(start 37.923724 -229.095046)
		(end 37.43071 -228.602032)
		(width 0.18288)
		(layer "In6.Cu")
		(net "M_C_CPU1_SB_DQS_DN<0>")
	)
	(segment
		(start 44.704508 -231.894126)
		(end 44.447714 -231.637078)
		(width 0.18288)
		(layer "In6.Cu")
		(net "M_C_CPU1_SB_DQS_DN<0>")
	)
	(segment
		(start 50.27168 -233.696002)
		(end 49.436274 -232.860596)
		(width 0.18288)
		(layer "In6.Cu")
		(net "M_C_CPU1_SB_DQS_DN<0>")
	)
	(segment
		(start 63.67399 -236.050582)
		(end 62.20333 -235.439966)
		(width 0.18288)
		(layer "In6.Cu")
		(net "M_C_CPU1_SB_DQS_DN<0>")
	)
	(segment
		(start 54.242208 -233.587544)
		(end 53.693568 -233.587544)
		(width 0.18288)
		(layer "In6.Cu")
		(net "M_C_CPU1_SB_DQS_DN<0>")
	)
	(segment
		(start 38.487858 -229.65918)
		(end 38.487858 -229.483158)
		(width 0.18288)
		(layer "In6.Cu")
		(net "M_C_CPU1_SB_DQS_DN<0>")
	)
	(segment
		(start 44.88053 -231.894126)
		(end 44.704508 -231.894126)
		(width 0.18288)
		(layer "In6.Cu")
		(net "M_C_CPU1_SB_DQS_DN<0>")
	)
	(segment
		(start 52.896008 -233.587544)
		(end 52.347368 -233.587544)
		(width 0.18288)
		(layer "In6.Cu")
		(net "M_C_CPU1_SB_DQS_DN<0>")
	)
	(segment
		(start 83.172554 -241.186462)
		(end 83.112864 -241.126772)
		(width 0.088646)
		(layer "In6.Cu")
		(net "M_C_CPU1_SB_DQS_DN<0>")
	)
	(segment
		(start 54.366668 -233.712004)
		(end 54.242208 -233.587544)
		(width 0.18288)
		(layer "In6.Cu")
		(net "M_C_CPU1_SB_DQS_DN<0>")
	)
	(segment
		(start 49.00041 -232.860596)
		(end 48.87595 -232.736136)
		(width 0.18288)
		(layer "In6.Cu")
		(net "M_C_CPU1_SB_DQS_DN<0>")
	)
	(segment
		(start 53.020468 -233.712004)
		(end 52.896008 -233.587544)
		(width 0.18288)
		(layer "In6.Cu")
		(net "M_C_CPU1_SB_DQS_DN<0>")
	)
	(segment
		(start 94.498668 -242.473734)
		(end 94.22511 -242.473734)
		(width 0.088646)
		(layer "In6.Cu")
		(net "M_C_CPU1_SB_DQS_DN<0>")
	)
	(segment
		(start 51.613054 -233.712004)
		(end 51.342798 -233.441748)
		(width 0.18288)
		(layer "In6.Cu")
		(net "M_C_CPU1_SB_DQS_DN<0>")
	)
	(segment
		(start 85.138514 -242.619276)
		(end 85.123782 -242.61064)
		(width 0.088646)
		(layer "In6.Cu")
		(net "M_C_CPU1_SB_DQS_DN<0>")
	)
	(segment
		(start 91.151456 -242.619784)
		(end 91.143328 -242.62461)
		(width 0.088646)
		(layer "In6.Cu")
		(net "M_C_CPU1_SB_DQS_DN<0>")
	)
	(segment
		(start 92.106496 -242.61064)
		(end 92.091764 -242.619276)
		(width 0.088646)
		(layer "In6.Cu")
		(net "M_C_CPU1_SB_DQS_DN<0>")
	)
	(segment
		(start 48.87595 -232.736136)
		(end 48.32731 -232.736136)
		(width 0.18288)
		(layer "In6.Cu")
		(net "M_C_CPU1_SB_DQS_DN<0>")
	)
	(segment
		(start 60.85713 -235.439966)
		(end 59.89574 -235.439966)
		(width 0.18288)
		(layer "In6.Cu")
		(net "M_C_CPU1_SB_DQS_DN<0>")
	)
	(segment
		(start 55.644542 -234.441238)
		(end 54.915308 -233.712004)
		(width 0.18288)
		(layer "In6.Cu")
		(net "M_C_CPU1_SB_DQS_DN<0>")
	)
	(segment
		(start 94.22511 -242.473734)
		(end 93.971872 -242.61953)
		(width 0.088646)
		(layer "In6.Cu")
		(net "M_C_CPU1_SB_DQS_DN<0>")
	)
	(segment
		(start 32.611822 -228.175312)
		(end 32.135318 -228.175312)
		(width 0.18288)
		(layer "In6.Cu")
		(net "M_C_CPU1_SB_DQS_DN<0>")
	)
	(segment
		(start 43.36669 -231.054148)
		(end 43.203876 -231.121458)
		(width 0.18288)
		(layer "In6.Cu")
		(net "M_C_CPU1_SB_DQS_DN<0>")
	)
	(segment
		(start 42.66438 -230.897938)
		(end 40.943276 -230.897938)
		(width 0.18288)
		(layer "In6.Cu")
		(net "M_C_CPU1_SB_DQS_DN<0>")
	)
	(segment
		(start 47.483522 -232.860596)
		(end 47.21479 -232.591864)
		(width 0.18288)
		(layer "In6.Cu")
		(net "M_C_CPU1_SB_DQS_DN<0>")
	)
	(segment
		(start 47.21479 -232.591864)
		(end 46.71314 -232.591864)
		(width 0.18288)
		(layer "In6.Cu")
		(net "M_C_CPU1_SB_DQS_DN<0>")
	)
	(segment
		(start 40.943276 -230.897938)
		(end 40.092376 -230.047038)
		(width 0.18288)
		(layer "In6.Cu")
		(net "M_C_CPU1_SB_DQS_DN<0>")
	)
	(segment
		(start 49.436274 -232.860596)
		(end 49.00041 -232.860596)
		(width 0.18288)
		(layer "In6.Cu")
		(net "M_C_CPU1_SB_DQS_DN<0>")
	)
	(segment
		(start 83.089496 -241.126772)
		(end 71.415148 -241.126772)
		(width 0.18288)
		(layer "In6.Cu")
		(net "M_C_CPU1_SB_DQS_DN<0>")
	)
	(segment
		(start 44.447714 -231.637078)
		(end 43.940984 -231.42702)
		(width 0.18288)
		(layer "In6.Cu")
		(net "M_C_CPU1_SB_DQS_DN<0>")
	)
	(segment
		(start 56.877712 -234.316778)
		(end 56.329072 -234.316778)
		(width 0.18288)
		(layer "In6.Cu")
		(net "M_C_CPU1_SB_DQS_DN<0>")
	)
	(segment
		(start 59.89574 -235.439966)
		(end 58.897012 -234.441238)
		(width 0.18288)
		(layer "In6.Cu")
		(net "M_C_CPU1_SB_DQS_DN<0>")
	)
	(segment
		(start 54.915308 -233.712004)
		(end 54.366668 -233.712004)
		(width 0.18288)
		(layer "In6.Cu")
		(net "M_C_CPU1_SB_DQS_DN<0>")
	)
	(segment
		(start 32.135318 -228.175312)
		(end 31.876746 -227.91674)
		(width 0.18288)
		(layer "In6.Cu")
		(net "M_C_CPU1_SB_DQS_DN<0>")
	)
	(segment
		(start 57.675272 -234.316778)
		(end 57.550812 -234.441238)
		(width 0.18288)
		(layer "In6.Cu")
		(net "M_C_CPU1_SB_DQS_DN<0>")
	)
	(arc
		(start 94.653354 -242.43284)
		(mid 94.578669 -242.463345)
		(end 94.498668 -242.473734)
		(width 0.088646)
		(layer "In6.Cu")
		(net "M_C_CPU1_SB_DQS_DN<0>")
	)
	(arc
		(start 89.837514 -242.61953)
		(mid 89.554529 -242.543754)
		(end 89.271602 -242.619784)
		(width 0.088646)
		(layer "In6.Cu")
		(net "M_C_CPU1_SB_DQS_DN<0>")
	)
	(arc
		(start 86.452964 -242.619276)
		(mid 86.265766 -242.669419)
		(end 86.078568 -242.619276)
		(width 0.088646)
		(layer "In6.Cu")
		(net "M_C_CPU1_SB_DQS_DN<0>")
	)
	(arc
		(start 93.596968 -242.619276)
		(mid 93.322739 -242.543351)
		(end 93.046296 -242.61064)
		(width 0.088646)
		(layer "In6.Cu")
		(net "M_C_CPU1_SB_DQS_DN<0>")
	)
	(arc
		(start 85.123782 -242.61064)
		(mid 84.847341 -242.543474)
		(end 84.57311 -242.619276)
		(width 0.088646)
		(layer "In6.Cu")
		(net "M_C_CPU1_SB_DQS_DN<0>")
	)
	(arc
		(start 87.958422 -242.619276)
		(mid 87.675466 -242.543407)
		(end 87.39251 -242.619276)
		(width 0.088646)
		(layer "In6.Cu")
		(net "M_C_CPU1_SB_DQS_DN<0>")
	)
	(arc
		(start 88.323674 -242.62461)
		(mid 88.140136 -242.669733)
		(end 87.957914 -242.61953)
		(width 0.088646)
		(layer "In6.Cu")
		(net "M_C_CPU1_SB_DQS_DN<0>")
	)
	(arc
		(start 86.068154 -242.61318)
		(mid 85.789722 -242.543366)
		(end 85.51291 -242.619276)
		(width 0.088646)
		(layer "In6.Cu")
		(net "M_C_CPU1_SB_DQS_DN<0>")
	)
	(arc
		(start 87.0077 -242.61318)
		(mid 86.729522 -242.543488)
		(end 86.452964 -242.619276)
		(width 0.088646)
		(layer "In6.Cu")
		(net "M_C_CPU1_SB_DQS_DN<0>")
	)
	(arc
		(start 90.77706 -242.61953)
		(mid 90.494184 -242.543754)
		(end 90.211402 -242.619784)
		(width 0.088646)
		(layer "In6.Cu")
		(net "M_C_CPU1_SB_DQS_DN<0>")
	)
	(arc
		(start 85.51291 -242.619276)
		(mid 85.325712 -242.669419)
		(end 85.138514 -242.619276)
		(width 0.088646)
		(layer "In6.Cu")
		(net "M_C_CPU1_SB_DQS_DN<0>")
	)
	(arc
		(start 88.897714 -242.61953)
		(mid 88.614729 -242.543754)
		(end 88.331802 -242.619784)
		(width 0.088646)
		(layer "In6.Cu")
		(net "M_C_CPU1_SB_DQS_DN<0>")
	)
	(arc
		(start 87.39251 -242.619276)
		(mid 87.205312 -242.669419)
		(end 87.018114 -242.619276)
		(width 0.088646)
		(layer "In6.Cu")
		(net "M_C_CPU1_SB_DQS_DN<0>")
	)
	(arc
		(start 92.657168 -242.619276)
		(mid 92.382939 -242.543351)
		(end 92.106496 -242.61064)
		(width 0.088646)
		(layer "In6.Cu")
		(net "M_C_CPU1_SB_DQS_DN<0>")
	)
	(arc
		(start 92.091764 -242.61953)
		(mid 91.909685 -242.669638)
		(end 91.726258 -242.62461)
		(width 0.088646)
		(layer "In6.Cu")
		(net "M_C_CPU1_SB_DQS_DN<0>")
	)
	(arc
		(start 89.259918 -242.626896)
		(mid 89.077858 -242.669916)
		(end 88.897714 -242.61953)
		(width 0.088646)
		(layer "In6.Cu")
		(net "M_C_CPU1_SB_DQS_DN<0>")
	)
	(arc
		(start 91.143328 -242.62461)
		(mid 90.959536 -242.669854)
		(end 90.77706 -242.61953)
		(width 0.088646)
		(layer "In6.Cu")
		(net "M_C_CPU1_SB_DQS_DN<0>")
	)
	(arc
		(start 90.199718 -242.626896)
		(mid 90.017658 -242.669916)
		(end 89.837514 -242.61953)
		(width 0.088646)
		(layer "In6.Cu")
		(net "M_C_CPU1_SB_DQS_DN<0>")
	)
	(arc
		(start 91.717622 -242.619784)
		(mid 91.434556 -242.543847)
		(end 91.151456 -242.619784)
		(width 0.088646)
		(layer "In6.Cu")
		(net "M_C_CPU1_SB_DQS_DN<0>")
	)
	(arc
		(start 84.57311 -242.619276)
		(mid 84.385912 -242.669419)
		(end 84.198714 -242.619276)
		(width 0.088646)
		(layer "In6.Cu")
		(net "M_C_CPU1_SB_DQS_DN<0>")
	)
	(arc
		(start 93.971618 -242.619276)
		(mid 93.78442 -242.669419)
		(end 93.597222 -242.619276)
		(width 0.088646)
		(layer "In6.Cu")
		(net "M_C_CPU1_SB_DQS_DN<0>")
	)
	(arc
		(start 93.031564 -242.619276)
		(mid 92.844366 -242.669419)
		(end 92.657168 -242.619276)
		(width 0.088646)
		(layer "In6.Cu")
		(net "M_C_CPU1_SB_DQS_DN<0>")
	)
	(arc
		(start 84.198714 -242.619276)
		(mid 84.157784 -242.592243)
		(end 84.120736 -242.560094)
		(width 0.088646)
		(layer "In6.Cu")
		(net "M_C_CPU1_SB_DQS_DN<0>")
	)
	(segment
		(start 25.595072 -220.68282)
		(end 26.20391 -220.68282)
		(width 0.20066)
		(layer "F.Cu")
		(net "M_C_CPU1_SB_DQ<9>")
	)
	(segment
		(start 25.27808 -221.32798)
		(end 25.432512 -221.173548)
		(width 0.20066)
		(layer "F.Cu")
		(net "M_C_CPU1_SB_DQ<9>")
	)
	(segment
		(start 29.13253 -221.116652)
		(end 30.771846 -221.116652)
		(width 0.20066)
		(layer "F.Cu")
		(net "M_C_CPU1_SB_DQ<9>")
	)
	(segment
		(start 23.228046 -221.116652)
		(end 24.562308 -221.116652)
		(width 0.20066)
		(layer "F.Cu")
		(net "M_C_CPU1_SB_DQ<9>")
	)
	(segment
		(start 95.193612 -238.76127)
		(end 95.193612 -238.225584)
		(width 0.20066)
		(layer "F.Cu")
		(net "M_C_CPU1_SB_DQ<9>")
	)
	(segment
		(start 24.773636 -221.32798)
		(end 25.27808 -221.32798)
		(width 0.20066)
		(layer "F.Cu")
		(net "M_C_CPU1_SB_DQ<9>")
	)
	(segment
		(start 25.432512 -221.173548)
		(end 25.432512 -220.84538)
		(width 0.20066)
		(layer "F.Cu")
		(net "M_C_CPU1_SB_DQ<9>")
	)
	(segment
		(start 25.432512 -220.84538)
		(end 25.595072 -220.68282)
		(width 0.20066)
		(layer "F.Cu")
		(net "M_C_CPU1_SB_DQ<9>")
	)
	(segment
		(start 28.707588 -220.69171)
		(end 29.13253 -221.116652)
		(width 0.20066)
		(layer "F.Cu")
		(net "M_C_CPU1_SB_DQ<9>")
	)
	(segment
		(start 95.193866 -238.761524)
		(end 95.193612 -238.76127)
		(width 0.20066)
		(layer "F.Cu")
		(net "M_C_CPU1_SB_DQ<9>")
	)
	(segment
		(start 28.529026 -220.69171)
		(end 28.707588 -220.69171)
		(width 0.20066)
		(layer "F.Cu")
		(net "M_C_CPU1_SB_DQ<9>")
	)
	(segment
		(start 28.198318 -220.69171)
		(end 28.529026 -220.69171)
		(width 0.101854)
		(layer "F.Cu")
		(net "M_C_CPU1_SB_DQ<9>")
	)
	(segment
		(start 26.2128 -220.69171)
		(end 28.198318 -220.69171)
		(width 0.1016)
		(layer "F.Cu")
		(net "M_C_CPU1_SB_DQ<9>")
	)
	(segment
		(start 24.562308 -221.116652)
		(end 24.773636 -221.32798)
		(width 0.20066)
		(layer "F.Cu")
		(net "M_C_CPU1_SB_DQ<9>")
	)
	(segment
		(start 26.20391 -220.68282)
		(end 26.2128 -220.69171)
		(width 0.1016)
		(layer "F.Cu")
		(net "M_C_CPU1_SB_DQ<9>")
	)
	(segment
		(start 31.876746 -221.116652)
		(end 30.771846 -221.116652)
		(width 0.20066)
		(layer "F.Cu")
		(net "M_C_CPU1_SB_DQ<9>")
	)
	(segment
		(start 51.955954 -224.704656)
		(end 51.719226 -224.941384)
		(width 0.18288)
		(layer "In6.Cu")
		(net "M_C_CPU1_SB_DQ<9>")
	)
	(segment
		(start 59.03595 -225.791522)
		(end 58.25236 -225.007932)
		(width 0.18288)
		(layer "In6.Cu")
		(net "M_C_CPU1_SB_DQ<9>")
	)
	(segment
		(start 34.554414 -220.092016)
		(end 34.371534 -220.274896)
		(width 0.18288)
		(layer "In6.Cu")
		(net "M_C_CPU1_SB_DQ<9>")
	)
	(segment
		(start 35.062414 -220.274896)
		(end 34.879534 -220.092016)
		(width 0.18288)
		(layer "In6.Cu")
		(net "M_C_CPU1_SB_DQ<9>")
	)
	(segment
		(start 83.099656 -236.600238)
		(end 83.01101 -236.511592)
		(width 0.088646)
		(layer "In6.Cu")
		(net "M_C_CPU1_SB_DQ<9>")
	)
	(segment
		(start 32.667448 -222.480124)
		(end 32.484568 -222.297244)
		(width 0.18288)
		(layer "In6.Cu")
		(net "M_C_CPU1_SB_DQ<9>")
	)
	(segment
		(start 90.226896 -238.723678)
		(end 90.212164 -238.715042)
		(width 0.088646)
		(layer "In6.Cu")
		(net "M_C_CPU1_SB_DQ<9>")
	)
	(segment
		(start 63.67526 -227.58654)
		(end 62.813438 -226.724718)
		(width 0.18288)
		(layer "In6.Cu")
		(net "M_C_CPU1_SB_DQ<9>")
	)
	(segment
		(start 85.043264 -237.901226)
		(end 85.031326 -237.894368)
		(width 0.088646)
		(layer "In6.Cu")
		(net "M_C_CPU1_SB_DQ<9>")
	)
	(segment
		(start 65.131442 -228.299518)
		(end 64.418464 -227.58654)
		(width 0.18288)
		(layer "In6.Cu")
		(net "M_C_CPU1_SB_DQ<9>")
	)
	(segment
		(start 65.131442 -228.75494)
		(end 65.131442 -228.299518)
		(width 0.18288)
		(layer "In6.Cu")
		(net "M_C_CPU1_SB_DQ<9>")
	)
	(segment
		(start 83.099656 -236.811312)
		(end 83.099656 -236.600238)
		(width 0.088646)
		(layer "In6.Cu")
		(net "M_C_CPU1_SB_DQ<9>")
	)
	(segment
		(start 93.981778 -238.721138)
		(end 93.971364 -238.715042)
		(width 0.088646)
		(layer "In6.Cu")
		(net "M_C_CPU1_SB_DQ<9>")
	)
	(segment
		(start 32.484568 -221.724474)
		(end 31.876746 -221.116652)
		(width 0.18288)
		(layer "In6.Cu")
		(net "M_C_CPU1_SB_DQ<9>")
	)
	(segment
		(start 84.385912 -237.977172)
		(end 83.812634 -237.977172)
		(width 0.088646)
		(layer "In6.Cu")
		(net "M_C_CPU1_SB_DQ<9>")
	)
	(segment
		(start 33.175448 -221.724474)
		(end 33.175448 -222.297244)
		(width 0.18288)
		(layer "In6.Cu")
		(net "M_C_CPU1_SB_DQ<9>")
	)
	(segment
		(start 33.175448 -222.297244)
		(end 32.992568 -222.480124)
		(width 0.18288)
		(layer "In6.Cu")
		(net "M_C_CPU1_SB_DQ<9>")
	)
	(segment
		(start 36.671758 -221.541594)
		(end 35.245294 -221.541594)
		(width 0.18288)
		(layer "In6.Cu")
		(net "M_C_CPU1_SB_DQ<9>")
	)
	(segment
		(start 34.371534 -220.274896)
		(end 34.371534 -221.358714)
		(width 0.18288)
		(layer "In6.Cu")
		(net "M_C_CPU1_SB_DQ<9>")
	)
	(segment
		(start 86.078568 -238.715042)
		(end 86.063836 -238.723678)
		(width 0.088646)
		(layer "In6.Cu")
		(net "M_C_CPU1_SB_DQ<9>")
	)
	(segment
		(start 34.879534 -220.092016)
		(end 34.554414 -220.092016)
		(width 0.18288)
		(layer "In6.Cu")
		(net "M_C_CPU1_SB_DQ<9>")
	)
	(segment
		(start 50.03673 -224.941384)
		(end 49.186846 -224.0915)
		(width 0.18288)
		(layer "In6.Cu")
		(net "M_C_CPU1_SB_DQ<9>")
	)
	(segment
		(start 32.484568 -222.297244)
		(end 32.484568 -221.724474)
		(width 0.18288)
		(layer "In6.Cu")
		(net "M_C_CPU1_SB_DQ<9>")
	)
	(segment
		(start 34.371534 -221.358714)
		(end 34.188654 -221.541594)
		(width 0.18288)
		(layer "In6.Cu")
		(net "M_C_CPU1_SB_DQ<9>")
	)
	(segment
		(start 66.34099 -229.19436)
		(end 65.570862 -229.19436)
		(width 0.18288)
		(layer "In6.Cu")
		(net "M_C_CPU1_SB_DQ<9>")
	)
	(segment
		(start 83.57108 -237.735618)
		(end 83.57108 -237.282736)
		(width 0.088646)
		(layer "In6.Cu")
		(net "M_C_CPU1_SB_DQ<9>")
	)
	(segment
		(start 85.23097 -238.241078)
		(end 85.23097 -238.225584)
		(width 0.088646)
		(layer "In6.Cu")
		(net "M_C_CPU1_SB_DQ<9>")
	)
	(segment
		(start 35.245294 -221.541594)
		(end 35.062414 -221.358714)
		(width 0.18288)
		(layer "In6.Cu")
		(net "M_C_CPU1_SB_DQ<9>")
	)
	(segment
		(start 41.426892 -222.180404)
		(end 41.045384 -222.180404)
		(width 0.18288)
		(layer "In6.Cu")
		(net "M_C_CPU1_SB_DQ<9>")
	)
	(segment
		(start 32.992568 -222.480124)
		(end 32.667448 -222.480124)
		(width 0.18288)
		(layer "In6.Cu")
		(net "M_C_CPU1_SB_DQ<9>")
	)
	(segment
		(start 49.186846 -224.0915)
		(end 45.985684 -224.0915)
		(width 0.18288)
		(layer "In6.Cu")
		(net "M_C_CPU1_SB_DQ<9>")
	)
	(segment
		(start 82.835496 -236.511592)
		(end 73.658222 -236.511592)
		(width 0.18288)
		(layer "In6.Cu")
		(net "M_C_CPU1_SB_DQ<9>")
	)
	(segment
		(start 51.719226 -224.941384)
		(end 50.03673 -224.941384)
		(width 0.18288)
		(layer "In6.Cu")
		(net "M_C_CPU1_SB_DQ<9>")
	)
	(segment
		(start 83.57108 -237.282736)
		(end 83.099656 -236.811312)
		(width 0.088646)
		(layer "In6.Cu")
		(net "M_C_CPU1_SB_DQ<9>")
	)
	(segment
		(start 73.658222 -236.511592)
		(end 66.34099 -229.19436)
		(width 0.18288)
		(layer "In6.Cu")
		(net "M_C_CPU1_SB_DQ<9>")
	)
	(segment
		(start 45.135546 -223.241362)
		(end 42.48785 -223.241362)
		(width 0.18288)
		(layer "In6.Cu")
		(net "M_C_CPU1_SB_DQ<9>")
	)
	(segment
		(start 34.188654 -221.541594)
		(end 33.358328 -221.541594)
		(width 0.18288)
		(layer "In6.Cu")
		(net "M_C_CPU1_SB_DQ<9>")
	)
	(segment
		(start 62.813438 -226.109276)
		(end 62.495684 -225.791522)
		(width 0.18288)
		(layer "In6.Cu")
		(net "M_C_CPU1_SB_DQ<9>")
	)
	(segment
		(start 83.01101 -236.511592)
		(end 82.835496 -236.511592)
		(width 0.088646)
		(layer "In6.Cu")
		(net "M_C_CPU1_SB_DQ<9>")
	)
	(segment
		(start 58.25236 -225.007932)
		(end 56.135778 -225.007932)
		(width 0.18288)
		(layer "In6.Cu")
		(net "M_C_CPU1_SB_DQ<9>")
	)
	(segment
		(start 87.018368 -238.715042)
		(end 87.003636 -238.723678)
		(width 0.088646)
		(layer "In6.Cu")
		(net "M_C_CPU1_SB_DQ<9>")
	)
	(segment
		(start 85.05571 -237.908338)
		(end 85.043264 -237.901226)
		(width 0.088646)
		(layer "In6.Cu")
		(net "M_C_CPU1_SB_DQ<9>")
	)
	(segment
		(start 33.358328 -221.541594)
		(end 33.175448 -221.724474)
		(width 0.18288)
		(layer "In6.Cu")
		(net "M_C_CPU1_SB_DQ<9>")
	)
	(segment
		(start 56.135778 -225.007932)
		(end 55.832502 -224.704656)
		(width 0.18288)
		(layer "In6.Cu")
		(net "M_C_CPU1_SB_DQ<9>")
	)
	(segment
		(start 42.48785 -223.241362)
		(end 41.426892 -222.180404)
		(width 0.18288)
		(layer "In6.Cu")
		(net "M_C_CPU1_SB_DQ<9>")
	)
	(segment
		(start 62.495684 -225.791522)
		(end 59.03595 -225.791522)
		(width 0.18288)
		(layer "In6.Cu")
		(net "M_C_CPU1_SB_DQ<9>")
	)
	(segment
		(start 35.062414 -221.358714)
		(end 35.062414 -220.274896)
		(width 0.18288)
		(layer "In6.Cu")
		(net "M_C_CPU1_SB_DQ<9>")
	)
	(segment
		(start 64.418464 -227.58654)
		(end 63.67526 -227.58654)
		(width 0.18288)
		(layer "In6.Cu")
		(net "M_C_CPU1_SB_DQ<9>")
	)
	(segment
		(start 83.812634 -237.977172)
		(end 83.57108 -237.735618)
		(width 0.088646)
		(layer "In6.Cu")
		(net "M_C_CPU1_SB_DQ<9>")
	)
	(segment
		(start 45.985684 -224.0915)
		(end 45.135546 -223.241362)
		(width 0.18288)
		(layer "In6.Cu")
		(net "M_C_CPU1_SB_DQ<9>")
	)
	(segment
		(start 55.832502 -224.704656)
		(end 51.955954 -224.704656)
		(width 0.18288)
		(layer "In6.Cu")
		(net "M_C_CPU1_SB_DQ<9>")
	)
	(segment
		(start 62.813438 -226.724718)
		(end 62.813438 -226.109276)
		(width 0.18288)
		(layer "In6.Cu")
		(net "M_C_CPU1_SB_DQ<9>")
	)
	(segment
		(start 65.570862 -229.19436)
		(end 65.131442 -228.75494)
		(width 0.18288)
		(layer "In6.Cu")
		(net "M_C_CPU1_SB_DQ<9>")
	)
	(segment
		(start 92.106496 -238.723678)
		(end 92.091764 -238.715042)
		(width 0.088646)
		(layer "In6.Cu")
		(net "M_C_CPU1_SB_DQ<9>")
	)
	(segment
		(start 88.347296 -238.723678)
		(end 88.332564 -238.715042)
		(width 0.088646)
		(layer "In6.Cu")
		(net "M_C_CPU1_SB_DQ<9>")
	)
	(segment
		(start 93.046296 -238.723678)
		(end 93.031564 -238.715042)
		(width 0.088646)
		(layer "In6.Cu")
		(net "M_C_CPU1_SB_DQ<9>")
	)
	(segment
		(start 36.912296 -221.301056)
		(end 36.671758 -221.541594)
		(width 0.18288)
		(layer "In6.Cu")
		(net "M_C_CPU1_SB_DQ<9>")
	)
	(segment
		(start 89.287096 -238.723678)
		(end 89.272364 -238.715042)
		(width 0.088646)
		(layer "In6.Cu")
		(net "M_C_CPU1_SB_DQ<9>")
	)
	(segment
		(start 40.166036 -221.301056)
		(end 36.912296 -221.301056)
		(width 0.18288)
		(layer "In6.Cu")
		(net "M_C_CPU1_SB_DQ<9>")
	)
	(segment
		(start 41.045384 -222.180404)
		(end 40.166036 -221.301056)
		(width 0.18288)
		(layer "In6.Cu")
		(net "M_C_CPU1_SB_DQ<9>")
	)
	(arc
		(start 87.003636 -238.723678)
		(mid 86.727161 -238.790998)
		(end 86.452964 -238.715042)
		(width 0.088646)
		(layer "In6.Cu")
		(net "M_C_CPU1_SB_DQ<9>")
	)
	(arc
		(start 88.897968 -238.715042)
		(mid 88.623769 -238.790877)
		(end 88.347296 -238.723678)
		(width 0.088646)
		(layer "In6.Cu")
		(net "M_C_CPU1_SB_DQ<9>")
	)
	(arc
		(start 93.596968 -238.715042)
		(mid 93.322769 -238.790877)
		(end 93.046296 -238.723678)
		(width 0.088646)
		(layer "In6.Cu")
		(net "M_C_CPU1_SB_DQ<9>")
	)
	(arc
		(start 92.657168 -238.715042)
		(mid 92.382969 -238.790877)
		(end 92.106496 -238.723678)
		(width 0.088646)
		(layer "In6.Cu")
		(net "M_C_CPU1_SB_DQ<9>")
	)
	(arc
		(start 92.091764 -238.715042)
		(mid 91.904566 -238.664899)
		(end 91.717368 -238.715042)
		(width 0.088646)
		(layer "In6.Cu")
		(net "M_C_CPU1_SB_DQ<9>")
	)
	(arc
		(start 91.151964 -238.715042)
		(mid 90.964766 -238.664899)
		(end 90.777568 -238.715042)
		(width 0.088646)
		(layer "In6.Cu")
		(net "M_C_CPU1_SB_DQ<9>")
	)
	(arc
		(start 85.031326 -237.894368)
		(mid 84.849215 -237.851043)
		(end 84.668868 -237.901226)
		(width 0.088646)
		(layer "In6.Cu")
		(net "M_C_CPU1_SB_DQ<9>")
	)
	(arc
		(start 89.837768 -238.715042)
		(mid 89.563569 -238.790877)
		(end 89.287096 -238.723678)
		(width 0.088646)
		(layer "In6.Cu")
		(net "M_C_CPU1_SB_DQ<9>")
	)
	(arc
		(start 90.212164 -238.715042)
		(mid 90.024966 -238.664899)
		(end 89.837768 -238.715042)
		(width 0.088646)
		(layer "In6.Cu")
		(net "M_C_CPU1_SB_DQ<9>")
	)
	(arc
		(start 93.971364 -238.715042)
		(mid 93.784166 -238.664899)
		(end 93.596968 -238.715042)
		(width 0.088646)
		(layer "In6.Cu")
		(net "M_C_CPU1_SB_DQ<9>")
	)
	(arc
		(start 87.392764 -238.715042)
		(mid 87.205566 -238.664899)
		(end 87.018368 -238.715042)
		(width 0.088646)
		(layer "In6.Cu")
		(net "M_C_CPU1_SB_DQ<9>")
	)
	(arc
		(start 89.272364 -238.715042)
		(mid 89.085166 -238.664899)
		(end 88.897968 -238.715042)
		(width 0.088646)
		(layer "In6.Cu")
		(net "M_C_CPU1_SB_DQ<9>")
	)
	(arc
		(start 93.031564 -238.715042)
		(mid 92.844366 -238.664899)
		(end 92.657168 -238.715042)
		(width 0.088646)
		(layer "In6.Cu")
		(net "M_C_CPU1_SB_DQ<9>")
	)
	(arc
		(start 84.668868 -237.901226)
		(mid 84.532396 -237.957849)
		(end 84.385912 -237.977172)
		(width 0.088646)
		(layer "In6.Cu")
		(net "M_C_CPU1_SB_DQ<9>")
	)
	(arc
		(start 95.193612 -238.225584)
		(mid 94.87933 -238.489468)
		(end 94.536514 -238.715042)
		(width 0.088646)
		(layer "In6.Cu")
		(net "M_C_CPU1_SB_DQ<9>")
	)
	(arc
		(start 88.332564 -238.715042)
		(mid 88.145366 -238.664899)
		(end 87.958168 -238.715042)
		(width 0.088646)
		(layer "In6.Cu")
		(net "M_C_CPU1_SB_DQ<9>")
	)
	(arc
		(start 85.23097 -238.225584)
		(mid 85.184233 -238.044378)
		(end 85.05571 -237.908338)
		(width 0.088646)
		(layer "In6.Cu")
		(net "M_C_CPU1_SB_DQ<9>")
	)
	(arc
		(start 86.452964 -238.715042)
		(mid 86.265766 -238.664899)
		(end 86.078568 -238.715042)
		(width 0.088646)
		(layer "In6.Cu")
		(net "M_C_CPU1_SB_DQ<9>")
	)
	(arc
		(start 91.717368 -238.715042)
		(mid 91.434666 -238.790818)
		(end 91.151964 -238.715042)
		(width 0.088646)
		(layer "In6.Cu")
		(net "M_C_CPU1_SB_DQ<9>")
	)
	(arc
		(start 86.063836 -238.723678)
		(mid 85.787361 -238.790998)
		(end 85.513164 -238.715042)
		(width 0.088646)
		(layer "In6.Cu")
		(net "M_C_CPU1_SB_DQ<9>")
	)
	(arc
		(start 87.958168 -238.715042)
		(mid 87.675466 -238.790818)
		(end 87.392764 -238.715042)
		(width 0.088646)
		(layer "In6.Cu")
		(net "M_C_CPU1_SB_DQ<9>")
	)
	(arc
		(start 90.777568 -238.715042)
		(mid 90.503369 -238.790877)
		(end 90.226896 -238.723678)
		(width 0.088646)
		(layer "In6.Cu")
		(net "M_C_CPU1_SB_DQ<9>")
	)
	(arc
		(start 94.536514 -238.715042)
		(mid 94.259955 -238.790785)
		(end 93.981778 -238.721138)
		(width 0.088646)
		(layer "In6.Cu")
		(net "M_C_CPU1_SB_DQ<9>")
	)
	(arc
		(start 85.513164 -238.715042)
		(mid 85.310341 -238.514811)
		(end 85.23097 -238.241078)
		(width 0.088646)
		(layer "In6.Cu")
		(net "M_C_CPU1_SB_DQ<9>")
	)
	(segment
		(start 26.212038 -222.391732)
		(end 26.459942 -222.391732)
		(width 0.101854)
		(layer "F.Cu")
		(net "M_C_CPU1_SB_DQ<8>")
	)
	(segment
		(start 28.977844 -222.391732)
		(end 29.402786 -222.816674)
		(width 0.20066)
		(layer "F.Cu")
		(net "M_C_CPU1_SB_DQ<8>")
	)
	(segment
		(start 24.801068 -223.055434)
		(end 25.259792 -223.055434)
		(width 0.20066)
		(layer "F.Cu")
		(net "M_C_CPU1_SB_DQ<8>")
	)
	(segment
		(start 31.876746 -222.816674)
		(end 30.771846 -222.816674)
		(width 0.20066)
		(layer "F.Cu")
		(net "M_C_CPU1_SB_DQ<8>")
	)
	(segment
		(start 26.20391 -222.383604)
		(end 26.212038 -222.391732)
		(width 0.101854)
		(layer "F.Cu")
		(net "M_C_CPU1_SB_DQ<8>")
	)
	(segment
		(start 25.432512 -222.882714)
		(end 25.432512 -222.593154)
		(width 0.20066)
		(layer "F.Cu")
		(net "M_C_CPU1_SB_DQ<8>")
	)
	(segment
		(start 24.562308 -222.816674)
		(end 24.801068 -223.055434)
		(width 0.20066)
		(layer "F.Cu")
		(net "M_C_CPU1_SB_DQ<8>")
	)
	(segment
		(start 25.259792 -223.055434)
		(end 25.432512 -222.882714)
		(width 0.20066)
		(layer "F.Cu")
		(net "M_C_CPU1_SB_DQ<8>")
	)
	(segment
		(start 28.529026 -222.391732)
		(end 28.977844 -222.391732)
		(width 0.20066)
		(layer "F.Cu")
		(net "M_C_CPU1_SB_DQ<8>")
	)
	(segment
		(start 23.228046 -222.816674)
		(end 24.562308 -222.816674)
		(width 0.20066)
		(layer "F.Cu")
		(net "M_C_CPU1_SB_DQ<8>")
	)
	(segment
		(start 95.663512 -239.57534)
		(end 95.663766 -239.575086)
		(width 0.20066)
		(layer "F.Cu")
		(net "M_C_CPU1_SB_DQ<8>")
	)
	(segment
		(start 95.663766 -239.575086)
		(end 95.663766 -239.0394)
		(width 0.20066)
		(layer "F.Cu")
		(net "M_C_CPU1_SB_DQ<8>")
	)
	(segment
		(start 29.402786 -222.816674)
		(end 30.771846 -222.816674)
		(width 0.20066)
		(layer "F.Cu")
		(net "M_C_CPU1_SB_DQ<8>")
	)
	(segment
		(start 25.642062 -222.383604)
		(end 26.20391 -222.383604)
		(width 0.20066)
		(layer "F.Cu")
		(net "M_C_CPU1_SB_DQ<8>")
	)
	(segment
		(start 25.432512 -222.593154)
		(end 25.642062 -222.383604)
		(width 0.20066)
		(layer "F.Cu")
		(net "M_C_CPU1_SB_DQ<8>")
	)
	(segment
		(start 26.459942 -222.391732)
		(end 28.529026 -222.391732)
		(width 0.1016)
		(layer "F.Cu")
		(net "M_C_CPU1_SB_DQ<8>")
	)
	(segment
		(start 53.598318 -226.824286)
		(end 53.598318 -227.108512)
		(width 0.18288)
		(layer "In6.Cu")
		(net "M_C_CPU1_SB_DQ<8>")
	)
	(segment
		(start 90.307668 -239.528858)
		(end 90.297254 -239.534954)
		(width 0.088646)
		(layer "In6.Cu")
		(net "M_C_CPU1_SB_DQ<8>")
	)
	(segment
		(start 33.866582 -223.825816)
		(end 33.683702 -224.008696)
		(width 0.18288)
		(layer "In6.Cu")
		(net "M_C_CPU1_SB_DQ<8>")
	)
	(segment
		(start 33.866582 -223.42475)
		(end 33.866582 -223.825816)
		(width 0.18288)
		(layer "In6.Cu")
		(net "M_C_CPU1_SB_DQ<8>")
	)
	(segment
		(start 54.95798 -226.641406)
		(end 53.781198 -226.641406)
		(width 0.18288)
		(layer "In6.Cu")
		(net "M_C_CPU1_SB_DQ<8>")
	)
	(segment
		(start 65.65138 -230.895144)
		(end 63.947802 -229.191566)
		(width 0.18288)
		(layer "In6.Cu")
		(net "M_C_CPU1_SB_DQ<8>")
	)
	(segment
		(start 43.482514 -224.99066)
		(end 42.977816 -224.99066)
		(width 0.18288)
		(layer "In6.Cu")
		(net "M_C_CPU1_SB_DQ<8>")
	)
	(segment
		(start 83.146138 -237.595918)
		(end 83.057492 -237.507272)
		(width 0.088646)
		(layer "In6.Cu")
		(net "M_C_CPU1_SB_DQ<8>")
	)
	(segment
		(start 42.104056 -224.80778)
		(end 41.921176 -224.99066)
		(width 0.18288)
		(layer "In6.Cu")
		(net "M_C_CPU1_SB_DQ<8>")
	)
	(segment
		(start 42.977816 -224.99066)
		(end 42.794936 -224.80778)
		(width 0.18288)
		(layer "In6.Cu")
		(net "M_C_CPU1_SB_DQ<8>")
	)
	(segment
		(start 85.608414 -239.528858)
		(end 85.593682 -239.537494)
		(width 0.088646)
		(layer "In6.Cu")
		(net "M_C_CPU1_SB_DQ<8>")
	)
	(segment
		(start 89.367614 -239.528858)
		(end 89.352882 -239.537494)
		(width 0.088646)
		(layer "In6.Cu")
		(net "M_C_CPU1_SB_DQ<8>")
	)
	(segment
		(start 83.89747 -238.66475)
		(end 83.146138 -237.913418)
		(width 0.088646)
		(layer "In6.Cu")
		(net "M_C_CPU1_SB_DQ<8>")
	)
	(segment
		(start 60.92063 -228.133656)
		(end 59.117484 -228.133656)
		(width 0.18288)
		(layer "In6.Cu")
		(net "M_C_CPU1_SB_DQ<8>")
	)
	(segment
		(start 49.24933 -225.791522)
		(end 44.283376 -225.791522)
		(width 0.18288)
		(layer "In6.Cu")
		(net "M_C_CPU1_SB_DQ<8>")
	)
	(segment
		(start 56.37911 -227.371656)
		(end 55.68823 -227.371656)
		(width 0.18288)
		(layer "In6.Cu")
		(net "M_C_CPU1_SB_DQ<8>")
	)
	(segment
		(start 61.6458 -229.191566)
		(end 61.48578 -229.031546)
		(width 0.18288)
		(layer "In6.Cu")
		(net "M_C_CPU1_SB_DQ<8>")
	)
	(segment
		(start 58.355484 -227.371656)
		(end 57.293764 -227.371656)
		(width 0.18288)
		(layer "In6.Cu")
		(net "M_C_CPU1_SB_DQ<8>")
	)
	(segment
		(start 37.679884 -223.018858)
		(end 36.900358 -223.018858)
		(width 0.18288)
		(layer "In6.Cu")
		(net "M_C_CPU1_SB_DQ<8>")
	)
	(segment
		(start 93.126814 -239.528858)
		(end 93.112082 -239.537494)
		(width 0.088646)
		(layer "In6.Cu")
		(net "M_C_CPU1_SB_DQ<8>")
	)
	(segment
		(start 42.286936 -224.312734)
		(end 42.104056 -224.495614)
		(width 0.18288)
		(layer "In6.Cu")
		(net "M_C_CPU1_SB_DQ<8>")
	)
	(segment
		(start 83.057492 -237.507272)
		(end 82.835496 -237.507272)
		(width 0.088646)
		(layer "In6.Cu")
		(net "M_C_CPU1_SB_DQ<8>")
	)
	(segment
		(start 87.488014 -239.528858)
		(end 87.473282 -239.537494)
		(width 0.088646)
		(layer "In6.Cu")
		(net "M_C_CPU1_SB_DQ<8>")
	)
	(segment
		(start 36.677346 -223.24187)
		(end 34.049462 -223.24187)
		(width 0.18288)
		(layer "In6.Cu")
		(net "M_C_CPU1_SB_DQ<8>")
	)
	(segment
		(start 44.283376 -225.791522)
		(end 43.482514 -224.99066)
		(width 0.18288)
		(layer "In6.Cu")
		(net "M_C_CPU1_SB_DQ<8>")
	)
	(segment
		(start 34.049462 -223.24187)
		(end 33.866582 -223.42475)
		(width 0.18288)
		(layer "In6.Cu")
		(net "M_C_CPU1_SB_DQ<8>")
	)
	(segment
		(start 95.018606 -239.521746)
		(end 95.006414 -239.528858)
		(width 0.088646)
		(layer "In6.Cu")
		(net "M_C_CPU1_SB_DQ<8>")
	)
	(segment
		(start 38.769798 -224.108772)
		(end 38.565836 -223.90481)
		(width 0.18288)
		(layer "In6.Cu")
		(net "M_C_CPU1_SB_DQ<8>")
	)
	(segment
		(start 84.76107 -239.0394)
		(end 84.76107 -239.031526)
		(width 0.088646)
		(layer "In6.Cu")
		(net "M_C_CPU1_SB_DQ<8>")
	)
	(segment
		(start 84.760816 -239.0394)
		(end 84.76107 -239.0394)
		(width 0.088646)
		(layer "In6.Cu")
		(net "M_C_CPU1_SB_DQ<8>")
	)
	(segment
		(start 42.794936 -224.80778)
		(end 42.794936 -224.495614)
		(width 0.18288)
		(layer "In6.Cu")
		(net "M_C_CPU1_SB_DQ<8>")
	)
	(segment
		(start 53.781198 -226.641406)
		(end 53.598318 -226.824286)
		(width 0.18288)
		(layer "In6.Cu")
		(net "M_C_CPU1_SB_DQ<8>")
	)
	(segment
		(start 37.91585 -223.254824)
		(end 37.679884 -223.018858)
		(width 0.18288)
		(layer "In6.Cu")
		(net "M_C_CPU1_SB_DQ<8>")
	)
	(segment
		(start 55.68823 -227.371656)
		(end 54.95798 -226.641406)
		(width 0.18288)
		(layer "In6.Cu")
		(net "M_C_CPU1_SB_DQ<8>")
	)
	(segment
		(start 53.415438 -227.291392)
		(end 53.090318 -227.291392)
		(width 0.18288)
		(layer "In6.Cu")
		(net "M_C_CPU1_SB_DQ<8>")
	)
	(segment
		(start 33.175702 -223.825816)
		(end 33.175702 -223.42475)
		(width 0.18288)
		(layer "In6.Cu")
		(net "M_C_CPU1_SB_DQ<8>")
	)
	(segment
		(start 38.832536 -223.186244)
		(end 38.63467 -222.988378)
		(width 0.18288)
		(layer "In6.Cu")
		(net "M_C_CPU1_SB_DQ<8>")
	)
	(segment
		(start 53.090318 -227.291392)
		(end 52.907438 -227.108512)
		(width 0.18288)
		(layer "In6.Cu")
		(net "M_C_CPU1_SB_DQ<8>")
	)
	(segment
		(start 91.247214 -239.528858)
		(end 91.2368 -239.534954)
		(width 0.088646)
		(layer "In6.Cu")
		(net "M_C_CPU1_SB_DQ<8>")
	)
	(segment
		(start 57.293764 -227.371656)
		(end 57.06999 -227.59543)
		(width 0.18288)
		(layer "In6.Cu")
		(net "M_C_CPU1_SB_DQ<8>")
	)
	(segment
		(start 38.63467 -222.988378)
		(end 38.40861 -222.988378)
		(width 0.18288)
		(layer "In6.Cu")
		(net "M_C_CPU1_SB_DQ<8>")
	)
	(segment
		(start 82.835496 -237.507272)
		(end 73.245726 -237.507272)
		(width 0.18288)
		(layer "In6.Cu")
		(net "M_C_CPU1_SB_DQ<8>")
	)
	(segment
		(start 94.066614 -239.528858)
		(end 94.051882 -239.537494)
		(width 0.088646)
		(layer "In6.Cu")
		(net "M_C_CPU1_SB_DQ<8>")
	)
	(segment
		(start 42.104056 -224.495614)
		(end 42.104056 -224.80778)
		(width 0.18288)
		(layer "In6.Cu")
		(net "M_C_CPU1_SB_DQ<8>")
	)
	(segment
		(start 61.48578 -228.698806)
		(end 60.92063 -228.133656)
		(width 0.18288)
		(layer "In6.Cu")
		(net "M_C_CPU1_SB_DQ<8>")
	)
	(segment
		(start 88.427814 -239.528858)
		(end 88.413082 -239.537494)
		(width 0.088646)
		(layer "In6.Cu")
		(net "M_C_CPU1_SB_DQ<8>")
	)
	(segment
		(start 33.683702 -224.008696)
		(end 33.358582 -224.008696)
		(width 0.18288)
		(layer "In6.Cu")
		(net "M_C_CPU1_SB_DQ<8>")
	)
	(segment
		(start 42.794936 -224.495614)
		(end 42.612056 -224.312734)
		(width 0.18288)
		(layer "In6.Cu")
		(net "M_C_CPU1_SB_DQ<8>")
	)
	(segment
		(start 73.245726 -237.507272)
		(end 66.633598 -230.895144)
		(width 0.18288)
		(layer "In6.Cu")
		(net "M_C_CPU1_SB_DQ<8>")
	)
	(segment
		(start 50.099214 -226.641406)
		(end 49.24933 -225.791522)
		(width 0.18288)
		(layer "In6.Cu")
		(net "M_C_CPU1_SB_DQ<8>")
	)
	(segment
		(start 53.598318 -227.108512)
		(end 53.415438 -227.291392)
		(width 0.18288)
		(layer "In6.Cu")
		(net "M_C_CPU1_SB_DQ<8>")
	)
	(segment
		(start 61.48578 -229.031546)
		(end 61.48578 -228.698806)
		(width 0.18288)
		(layer "In6.Cu")
		(net "M_C_CPU1_SB_DQ<8>")
	)
	(segment
		(start 41.921176 -224.99066)
		(end 41.149016 -224.99066)
		(width 0.18288)
		(layer "In6.Cu")
		(net "M_C_CPU1_SB_DQ<8>")
	)
	(segment
		(start 41.149016 -224.99066)
		(end 40.267128 -224.108772)
		(width 0.18288)
		(layer "In6.Cu")
		(net "M_C_CPU1_SB_DQ<8>")
	)
	(segment
		(start 86.548214 -239.528858)
		(end 86.533482 -239.537494)
		(width 0.088646)
		(layer "In6.Cu")
		(net "M_C_CPU1_SB_DQ<8>")
	)
	(segment
		(start 32.992822 -223.24187)
		(end 32.301942 -223.24187)
		(width 0.18288)
		(layer "In6.Cu")
		(net "M_C_CPU1_SB_DQ<8>")
	)
	(segment
		(start 33.175702 -223.42475)
		(end 32.992822 -223.24187)
		(width 0.18288)
		(layer "In6.Cu")
		(net "M_C_CPU1_SB_DQ<8>")
	)
	(segment
		(start 56.602884 -227.59543)
		(end 56.37911 -227.371656)
		(width 0.18288)
		(layer "In6.Cu")
		(net "M_C_CPU1_SB_DQ<8>")
	)
	(segment
		(start 32.301942 -223.24187)
		(end 31.876746 -222.816674)
		(width 0.18288)
		(layer "In6.Cu")
		(net "M_C_CPU1_SB_DQ<8>")
	)
	(segment
		(start 66.633598 -230.895144)
		(end 65.65138 -230.895144)
		(width 0.18288)
		(layer "In6.Cu")
		(net "M_C_CPU1_SB_DQ<8>")
	)
	(segment
		(start 38.14191 -223.254824)
		(end 37.91585 -223.254824)
		(width 0.18288)
		(layer "In6.Cu")
		(net "M_C_CPU1_SB_DQ<8>")
	)
	(segment
		(start 63.947802 -229.191566)
		(end 61.6458 -229.191566)
		(width 0.18288)
		(layer "In6.Cu")
		(net "M_C_CPU1_SB_DQ<8>")
	)
	(segment
		(start 40.267128 -224.108772)
		(end 38.769798 -224.108772)
		(width 0.18288)
		(layer "In6.Cu")
		(net "M_C_CPU1_SB_DQ<8>")
	)
	(segment
		(start 59.117484 -228.133656)
		(end 58.355484 -227.371656)
		(width 0.18288)
		(layer "In6.Cu")
		(net "M_C_CPU1_SB_DQ<8>")
	)
	(segment
		(start 84.386166 -238.66475)
		(end 83.89747 -238.66475)
		(width 0.088646)
		(layer "In6.Cu")
		(net "M_C_CPU1_SB_DQ<8>")
	)
	(segment
		(start 36.900358 -223.018858)
		(end 36.677346 -223.24187)
		(width 0.18288)
		(layer "In6.Cu")
		(net "M_C_CPU1_SB_DQ<8>")
	)
	(segment
		(start 92.187014 -239.528858)
		(end 92.172282 -239.537494)
		(width 0.088646)
		(layer "In6.Cu")
		(net "M_C_CPU1_SB_DQ<8>")
	)
	(segment
		(start 84.760816 -239.054894)
		(end 84.760816 -239.0394)
		(width 0.088646)
		(layer "In6.Cu")
		(net "M_C_CPU1_SB_DQ<8>")
	)
	(segment
		(start 57.06999 -227.59543)
		(end 56.602884 -227.59543)
		(width 0.18288)
		(layer "In6.Cu")
		(net "M_C_CPU1_SB_DQ<8>")
	)
	(segment
		(start 42.612056 -224.312734)
		(end 42.286936 -224.312734)
		(width 0.18288)
		(layer "In6.Cu")
		(net "M_C_CPU1_SB_DQ<8>")
	)
	(segment
		(start 38.565836 -223.67875)
		(end 38.832536 -223.412304)
		(width 0.18288)
		(layer "In6.Cu")
		(net "M_C_CPU1_SB_DQ<8>")
	)
	(segment
		(start 38.40861 -222.988378)
		(end 38.14191 -223.254824)
		(width 0.18288)
		(layer "In6.Cu")
		(net "M_C_CPU1_SB_DQ<8>")
	)
	(segment
		(start 33.358582 -224.008696)
		(end 33.175702 -223.825816)
		(width 0.18288)
		(layer "In6.Cu")
		(net "M_C_CPU1_SB_DQ<8>")
	)
	(segment
		(start 38.832536 -223.412304)
		(end 38.832536 -223.186244)
		(width 0.18288)
		(layer "In6.Cu")
		(net "M_C_CPU1_SB_DQ<8>")
	)
	(segment
		(start 38.565836 -223.90481)
		(end 38.565836 -223.67875)
		(width 0.18288)
		(layer "In6.Cu")
		(net "M_C_CPU1_SB_DQ<8>")
	)
	(segment
		(start 52.907438 -226.824286)
		(end 52.724558 -226.641406)
		(width 0.18288)
		(layer "In6.Cu")
		(net "M_C_CPU1_SB_DQ<8>")
	)
	(segment
		(start 52.724558 -226.641406)
		(end 50.099214 -226.641406)
		(width 0.18288)
		(layer "In6.Cu")
		(net "M_C_CPU1_SB_DQ<8>")
	)
	(segment
		(start 83.146138 -237.913418)
		(end 83.146138 -237.595918)
		(width 0.088646)
		(layer "In6.Cu")
		(net "M_C_CPU1_SB_DQ<8>")
	)
	(segment
		(start 52.907438 -227.108512)
		(end 52.907438 -226.824286)
		(width 0.18288)
		(layer "In6.Cu")
		(net "M_C_CPU1_SB_DQ<8>")
	)
	(arc
		(start 84.76107 -239.031526)
		(mid 84.648436 -238.771636)
		(end 84.386166 -238.66475)
		(width 0.088646)
		(layer "In6.Cu")
		(net "M_C_CPU1_SB_DQ<8>")
	)
	(arc
		(start 94.051882 -239.537494)
		(mid 93.775407 -239.604814)
		(end 93.50121 -239.528858)
		(width 0.088646)
		(layer "In6.Cu")
		(net "M_C_CPU1_SB_DQ<8>")
	)
	(arc
		(start 93.112082 -239.537494)
		(mid 92.835607 -239.604814)
		(end 92.56141 -239.528858)
		(width 0.088646)
		(layer "In6.Cu")
		(net "M_C_CPU1_SB_DQ<8>")
	)
	(arc
		(start 91.62161 -239.528858)
		(mid 91.434412 -239.478715)
		(end 91.247214 -239.528858)
		(width 0.088646)
		(layer "In6.Cu")
		(net "M_C_CPU1_SB_DQ<8>")
	)
	(arc
		(start 85.04301 -239.528858)
		(mid 84.840187 -239.328627)
		(end 84.760816 -239.054894)
		(width 0.088646)
		(layer "In6.Cu")
		(net "M_C_CPU1_SB_DQ<8>")
	)
	(arc
		(start 89.352882 -239.537494)
		(mid 89.076407 -239.604814)
		(end 88.80221 -239.528858)
		(width 0.088646)
		(layer "In6.Cu")
		(net "M_C_CPU1_SB_DQ<8>")
	)
	(arc
		(start 90.297254 -239.534954)
		(mid 90.018822 -239.6048)
		(end 89.74201 -239.528858)
		(width 0.088646)
		(layer "In6.Cu")
		(net "M_C_CPU1_SB_DQ<8>")
	)
	(arc
		(start 86.533482 -239.537494)
		(mid 86.257007 -239.604814)
		(end 85.98281 -239.528858)
		(width 0.088646)
		(layer "In6.Cu")
		(net "M_C_CPU1_SB_DQ<8>")
	)
	(arc
		(start 89.74201 -239.528858)
		(mid 89.554812 -239.478715)
		(end 89.367614 -239.528858)
		(width 0.088646)
		(layer "In6.Cu")
		(net "M_C_CPU1_SB_DQ<8>")
	)
	(arc
		(start 92.56141 -239.528858)
		(mid 92.374212 -239.478715)
		(end 92.187014 -239.528858)
		(width 0.088646)
		(layer "In6.Cu")
		(net "M_C_CPU1_SB_DQ<8>")
	)
	(arc
		(start 92.172282 -239.537494)
		(mid 91.895807 -239.604814)
		(end 91.62161 -239.528858)
		(width 0.088646)
		(layer "In6.Cu")
		(net "M_C_CPU1_SB_DQ<8>")
	)
	(arc
		(start 88.80221 -239.528858)
		(mid 88.615012 -239.478715)
		(end 88.427814 -239.528858)
		(width 0.088646)
		(layer "In6.Cu")
		(net "M_C_CPU1_SB_DQ<8>")
	)
	(arc
		(start 95.663766 -239.0394)
		(mid 95.354935 -239.298963)
		(end 95.018606 -239.521746)
		(width 0.088646)
		(layer "In6.Cu")
		(net "M_C_CPU1_SB_DQ<8>")
	)
	(arc
		(start 90.682064 -239.528858)
		(mid 90.494866 -239.478715)
		(end 90.307668 -239.528858)
		(width 0.088646)
		(layer "In6.Cu")
		(net "M_C_CPU1_SB_DQ<8>")
	)
	(arc
		(start 86.92261 -239.528858)
		(mid 86.735412 -239.478715)
		(end 86.548214 -239.528858)
		(width 0.088646)
		(layer "In6.Cu")
		(net "M_C_CPU1_SB_DQ<8>")
	)
	(arc
		(start 87.473282 -239.537494)
		(mid 87.196807 -239.604814)
		(end 86.92261 -239.528858)
		(width 0.088646)
		(layer "In6.Cu")
		(net "M_C_CPU1_SB_DQ<8>")
	)
	(arc
		(start 88.413082 -239.537494)
		(mid 88.136607 -239.604814)
		(end 87.86241 -239.528858)
		(width 0.088646)
		(layer "In6.Cu")
		(net "M_C_CPU1_SB_DQ<8>")
	)
	(arc
		(start 91.2368 -239.534954)
		(mid 90.958622 -239.604677)
		(end 90.682064 -239.528858)
		(width 0.088646)
		(layer "In6.Cu")
		(net "M_C_CPU1_SB_DQ<8>")
	)
	(arc
		(start 85.593682 -239.537494)
		(mid 85.317207 -239.604814)
		(end 85.04301 -239.528858)
		(width 0.088646)
		(layer "In6.Cu")
		(net "M_C_CPU1_SB_DQ<8>")
	)
	(arc
		(start 87.86241 -239.528858)
		(mid 87.675212 -239.478715)
		(end 87.488014 -239.528858)
		(width 0.088646)
		(layer "In6.Cu")
		(net "M_C_CPU1_SB_DQ<8>")
	)
	(arc
		(start 85.98281 -239.528858)
		(mid 85.795612 -239.478715)
		(end 85.608414 -239.528858)
		(width 0.088646)
		(layer "In6.Cu")
		(net "M_C_CPU1_SB_DQ<8>")
	)
	(arc
		(start 95.006414 -239.528858)
		(mid 94.723712 -239.604634)
		(end 94.44101 -239.528858)
		(width 0.088646)
		(layer "In6.Cu")
		(net "M_C_CPU1_SB_DQ<8>")
	)
	(arc
		(start 93.50121 -239.528858)
		(mid 93.314012 -239.478715)
		(end 93.126814 -239.528858)
		(width 0.088646)
		(layer "In6.Cu")
		(net "M_C_CPU1_SB_DQ<8>")
	)
	(arc
		(start 94.44101 -239.528858)
		(mid 94.253812 -239.478715)
		(end 94.066614 -239.528858)
		(width 0.088646)
		(layer "In6.Cu")
		(net "M_C_CPU1_SB_DQ<8>")
	)
	(segment
		(start 29.151326 -223.96323)
		(end 29.29382 -224.105724)
		(width 0.20066)
		(layer "F.Cu")
		(net "M_C_CPU1_SB_DQ<7>")
	)
	(segment
		(start 29.025342 -223.666558)
		(end 29.151326 -223.792542)
		(width 0.20066)
		(layer "F.Cu")
		(net "M_C_CPU1_SB_DQ<7>")
	)
	(segment
		(start 27.328114 -223.666558)
		(end 29.025342 -223.666558)
		(width 0.20066)
		(layer "F.Cu")
		(net "M_C_CPU1_SB_DQ<7>")
	)
	(segment
		(start 29.647642 -224.105724)
		(end 29.661866 -224.0915)
		(width 0.101854)
		(layer "F.Cu")
		(net "M_C_CPU1_SB_DQ<7>")
	)
	(segment
		(start 33.189926 -223.66224)
		(end 33.401762 -223.874076)
		(width 0.20066)
		(layer "F.Cu")
		(net "M_C_CPU1_SB_DQ<7>")
	)
	(segment
		(start 33.848294 -223.874076)
		(end 34.055812 -223.666558)
		(width 0.20066)
		(layer "F.Cu")
		(net "M_C_CPU1_SB_DQ<7>")
	)
	(segment
		(start 31.972758 -224.0915)
		(end 32.51708 -224.0915)
		(width 0.20066)
		(layer "F.Cu")
		(net "M_C_CPU1_SB_DQ<7>")
	)
	(segment
		(start 29.661866 -224.0915)
		(end 29.899864 -224.0915)
		(width 0.101854)
		(layer "F.Cu")
		(net "M_C_CPU1_SB_DQ<7>")
	)
	(segment
		(start 29.899864 -224.0915)
		(end 31.972758 -224.0915)
		(width 0.1016)
		(layer "F.Cu")
		(net "M_C_CPU1_SB_DQ<7>")
	)
	(segment
		(start 29.29382 -224.105724)
		(end 29.647642 -224.105724)
		(width 0.20066)
		(layer "F.Cu")
		(net "M_C_CPU1_SB_DQ<7>")
	)
	(segment
		(start 35.976814 -223.666558)
		(end 34.871914 -223.666558)
		(width 0.20066)
		(layer "F.Cu")
		(net "M_C_CPU1_SB_DQ<7>")
	)
	(segment
		(start 32.51708 -224.0915)
		(end 32.666178 -223.942402)
		(width 0.20066)
		(layer "F.Cu")
		(net "M_C_CPU1_SB_DQ<7>")
	)
	(segment
		(start 96.603566 -241.202972)
		(end 96.603566 -240.667286)
		(width 0.20066)
		(layer "F.Cu")
		(net "M_C_CPU1_SB_DQ<7>")
	)
	(segment
		(start 33.401762 -223.874076)
		(end 33.848294 -223.874076)
		(width 0.20066)
		(layer "F.Cu")
		(net "M_C_CPU1_SB_DQ<7>")
	)
	(segment
		(start 32.666178 -223.942402)
		(end 32.666178 -223.790764)
		(width 0.20066)
		(layer "F.Cu")
		(net "M_C_CPU1_SB_DQ<7>")
	)
	(segment
		(start 32.666178 -223.790764)
		(end 32.794702 -223.66224)
		(width 0.20066)
		(layer "F.Cu")
		(net "M_C_CPU1_SB_DQ<7>")
	)
	(segment
		(start 96.603312 -241.203226)
		(end 96.603566 -241.202972)
		(width 0.20066)
		(layer "F.Cu")
		(net "M_C_CPU1_SB_DQ<7>")
	)
	(segment
		(start 29.151326 -223.792542)
		(end 29.151326 -223.96323)
		(width 0.20066)
		(layer "F.Cu")
		(net "M_C_CPU1_SB_DQ<7>")
	)
	(segment
		(start 34.055812 -223.666558)
		(end 34.871914 -223.666558)
		(width 0.20066)
		(layer "F.Cu")
		(net "M_C_CPU1_SB_DQ<7>")
	)
	(segment
		(start 32.794702 -223.66224)
		(end 33.189926 -223.66224)
		(width 0.20066)
		(layer "F.Cu")
		(net "M_C_CPU1_SB_DQ<7>")
	)
	(segment
		(start 40.76446 -225.788982)
		(end 39.883334 -224.907856)
		(width 0.18288)
		(layer "In6.Cu")
		(net "M_C_CPU1_SB_DQ<7>")
	)
	(segment
		(start 54.084728 -227.814632)
		(end 53.88991 -228.00945)
		(width 0.18288)
		(layer "In6.Cu")
		(net "M_C_CPU1_SB_DQ<7>")
	)
	(segment
		(start 85.052154 -240.171478)
		(end 85.04174 -240.177574)
		(width 0.088646)
		(layer "In6.Cu")
		(net "M_C_CPU1_SB_DQ<7>")
	)
	(segment
		(start 84.589112 -240.118392)
		(end 84.313522 -239.842802)
		(width 0.088646)
		(layer "In6.Cu")
		(net "M_C_CPU1_SB_DQ<7>")
	)
	(segment
		(start 88.427814 -240.177574)
		(end 88.40978 -240.16716)
		(width 0.088646)
		(layer "In6.Cu")
		(net "M_C_CPU1_SB_DQ<7>")
	)
	(segment
		(start 95.946214 -240.177574)
		(end 95.931482 -240.168938)
		(width 0.088646)
		(layer "In6.Cu")
		(net "M_C_CPU1_SB_DQ<7>")
	)
	(segment
		(start 84.077048 -239.272064)
		(end 83.104736 -238.299752)
		(width 0.088646)
		(layer "In6.Cu")
		(net "M_C_CPU1_SB_DQ<7>")
	)
	(segment
		(start 52.50307 -228.49586)
		(end 52.34305 -228.65588)
		(width 0.18288)
		(layer "In6.Cu")
		(net "M_C_CPU1_SB_DQ<7>")
	)
	(segment
		(start 94.066614 -240.177574)
		(end 94.051882 -240.168938)
		(width 0.088646)
		(layer "In6.Cu")
		(net "M_C_CPU1_SB_DQ<7>")
	)
	(segment
		(start 84.313522 -239.842802)
		(end 84.077048 -239.272064)
		(width 0.088646)
		(layer "In6.Cu")
		(net "M_C_CPU1_SB_DQ<7>")
	)
	(segment
		(start 95.006414 -240.177574)
		(end 94.991682 -240.168938)
		(width 0.088646)
		(layer "In6.Cu")
		(net "M_C_CPU1_SB_DQ<7>")
	)
	(segment
		(start 86.94039 -240.16716)
		(end 86.922356 -240.177574)
		(width 0.088646)
		(layer "In6.Cu")
		(net "M_C_CPU1_SB_DQ<7>")
	)
	(segment
		(start 57.049924 -229.009956)
		(end 56.867044 -229.192836)
		(width 0.18288)
		(layer "In6.Cu")
		(net "M_C_CPU1_SB_DQ<7>")
	)
	(segment
		(start 38.431216 -224.907856)
		(end 37.778436 -224.255076)
		(width 0.18288)
		(layer "In6.Cu")
		(net "M_C_CPU1_SB_DQ<7>")
	)
	(segment
		(start 90.692478 -240.171478)
		(end 90.682064 -240.177574)
		(width 0.088646)
		(layer "In6.Cu")
		(net "M_C_CPU1_SB_DQ<7>")
	)
	(segment
		(start 55.973472 -229.192836)
		(end 55.436516 -228.65588)
		(width 0.18288)
		(layer "In6.Cu")
		(net "M_C_CPU1_SB_DQ<7>")
	)
	(segment
		(start 57.740804 -229.009956)
		(end 57.740804 -228.603048)
		(width 0.18288)
		(layer "In6.Cu")
		(net "M_C_CPU1_SB_DQ<7>")
	)
	(segment
		(start 37.778436 -224.255076)
		(end 36.565332 -224.255076)
		(width 0.18288)
		(layer "In6.Cu")
		(net "M_C_CPU1_SB_DQ<7>")
	)
	(segment
		(start 83.104736 -238.299752)
		(end 82.835496 -238.299752)
		(width 0.088646)
		(layer "In6.Cu")
		(net "M_C_CPU1_SB_DQ<7>")
	)
	(segment
		(start 86.922356 -240.177574)
		(end 86.907878 -240.185956)
		(width 0.088646)
		(layer "In6.Cu")
		(net "M_C_CPU1_SB_DQ<7>")
	)
	(segment
		(start 96.603566 -240.667286)
		(end 96.290892 -240.667286)
		(width 0.088646)
		(layer "In6.Cu")
		(net "M_C_CPU1_SB_DQ<7>")
	)
	(segment
		(start 53.72989 -228.65588)
		(end 53.35651 -228.65588)
		(width 0.18288)
		(layer "In6.Cu")
		(net "M_C_CPU1_SB_DQ<7>")
	)
	(segment
		(start 36.565332 -224.255076)
		(end 35.976814 -223.666558)
		(width 0.18288)
		(layer "In6.Cu")
		(net "M_C_CPU1_SB_DQ<7>")
	)
	(segment
		(start 57.740804 -228.603048)
		(end 57.557924 -228.420168)
		(width 0.18288)
		(layer "In6.Cu")
		(net "M_C_CPU1_SB_DQ<7>")
	)
	(segment
		(start 64.237616 -231.054656)
		(end 63.73749 -231.054656)
		(width 0.18288)
		(layer "In6.Cu")
		(net "M_C_CPU1_SB_DQ<7>")
	)
	(segment
		(start 53.88991 -228.49586)
		(end 53.72989 -228.65588)
		(width 0.18288)
		(layer "In6.Cu")
		(net "M_C_CPU1_SB_DQ<7>")
	)
	(segment
		(start 52.50307 -228.243892)
		(end 52.50307 -228.49586)
		(width 0.18288)
		(layer "In6.Cu")
		(net "M_C_CPU1_SB_DQ<7>")
	)
	(segment
		(start 57.049924 -228.603048)
		(end 57.049924 -229.009956)
		(width 0.18288)
		(layer "In6.Cu")
		(net "M_C_CPU1_SB_DQ<7>")
	)
	(segment
		(start 93.126814 -240.177574)
		(end 93.112082 -240.168938)
		(width 0.088646)
		(layer "In6.Cu")
		(net "M_C_CPU1_SB_DQ<7>")
	)
	(segment
		(start 54.74335 -228.65588)
		(end 54.58333 -228.49586)
		(width 0.18288)
		(layer "In6.Cu")
		(net "M_C_CPU1_SB_DQ<7>")
	)
	(segment
		(start 84.589112 -240.118646)
		(end 84.589112 -240.118392)
		(width 0.088646)
		(layer "In6.Cu")
		(net "M_C_CPU1_SB_DQ<7>")
	)
	(segment
		(start 53.35651 -228.65588)
		(end 53.19649 -228.49586)
		(width 0.18288)
		(layer "In6.Cu")
		(net "M_C_CPU1_SB_DQ<7>")
	)
	(segment
		(start 62.724284 -230.04145)
		(end 61.013594 -230.04145)
		(width 0.18288)
		(layer "In6.Cu")
		(net "M_C_CPU1_SB_DQ<7>")
	)
	(segment
		(start 52.021486 -228.65588)
		(end 51.70678 -228.341174)
		(width 0.18288)
		(layer "In6.Cu")
		(net "M_C_CPU1_SB_DQ<7>")
	)
	(segment
		(start 54.58333 -227.974652)
		(end 54.42331 -227.814632)
		(width 0.18288)
		(layer "In6.Cu")
		(net "M_C_CPU1_SB_DQ<7>")
	)
	(segment
		(start 48.498252 -226.641152)
		(end 43.255184 -226.641152)
		(width 0.18288)
		(layer "In6.Cu")
		(net "M_C_CPU1_SB_DQ<7>")
	)
	(segment
		(start 61.013594 -230.04145)
		(end 60.16498 -229.192836)
		(width 0.18288)
		(layer "In6.Cu")
		(net "M_C_CPU1_SB_DQ<7>")
	)
	(segment
		(start 43.255184 -226.641152)
		(end 42.403014 -225.788982)
		(width 0.18288)
		(layer "In6.Cu")
		(net "M_C_CPU1_SB_DQ<7>")
	)
	(segment
		(start 57.923684 -229.192836)
		(end 57.740804 -229.009956)
		(width 0.18288)
		(layer "In6.Cu")
		(net "M_C_CPU1_SB_DQ<7>")
	)
	(segment
		(start 55.436516 -228.65588)
		(end 54.74335 -228.65588)
		(width 0.18288)
		(layer "In6.Cu")
		(net "M_C_CPU1_SB_DQ<7>")
	)
	(segment
		(start 52.34305 -228.65588)
		(end 52.021486 -228.65588)
		(width 0.18288)
		(layer "In6.Cu")
		(net "M_C_CPU1_SB_DQ<7>")
	)
	(segment
		(start 54.42331 -227.814632)
		(end 54.084728 -227.814632)
		(width 0.18288)
		(layer "In6.Cu")
		(net "M_C_CPU1_SB_DQ<7>")
	)
	(segment
		(start 53.88991 -228.00945)
		(end 53.88991 -228.49586)
		(width 0.18288)
		(layer "In6.Cu")
		(net "M_C_CPU1_SB_DQ<7>")
	)
	(segment
		(start 63.73749 -231.054656)
		(end 62.724284 -230.04145)
		(width 0.18288)
		(layer "In6.Cu")
		(net "M_C_CPU1_SB_DQ<7>")
	)
	(segment
		(start 90.307668 -240.177574)
		(end 90.297254 -240.171478)
		(width 0.088646)
		(layer "In6.Cu")
		(net "M_C_CPU1_SB_DQ<7>")
	)
	(segment
		(start 42.403014 -225.788982)
		(end 40.76446 -225.788982)
		(width 0.18288)
		(layer "In6.Cu")
		(net "M_C_CPU1_SB_DQ<7>")
	)
	(segment
		(start 50.198274 -228.341174)
		(end 48.498252 -226.641152)
		(width 0.18288)
		(layer "In6.Cu")
		(net "M_C_CPU1_SB_DQ<7>")
	)
	(segment
		(start 60.16498 -229.192836)
		(end 57.923684 -229.192836)
		(width 0.18288)
		(layer "In6.Cu")
		(net "M_C_CPU1_SB_DQ<7>")
	)
	(segment
		(start 89.367614 -240.177574)
		(end 89.352882 -240.168938)
		(width 0.088646)
		(layer "In6.Cu")
		(net "M_C_CPU1_SB_DQ<7>")
	)
	(segment
		(start 39.883334 -224.907856)
		(end 38.431216 -224.907856)
		(width 0.18288)
		(layer "In6.Cu")
		(net "M_C_CPU1_SB_DQ<7>")
	)
	(segment
		(start 51.70678 -228.341174)
		(end 50.198274 -228.341174)
		(width 0.18288)
		(layer "In6.Cu")
		(net "M_C_CPU1_SB_DQ<7>")
	)
	(segment
		(start 96.290892 -240.667286)
		(end 96.22536 -240.601754)
		(width 0.088646)
		(layer "In6.Cu")
		(net "M_C_CPU1_SB_DQ<7>")
	)
	(segment
		(start 92.187014 -240.177574)
		(end 92.172282 -240.168938)
		(width 0.088646)
		(layer "In6.Cu")
		(net "M_C_CPU1_SB_DQ<7>")
	)
	(segment
		(start 53.03647 -228.083872)
		(end 52.66309 -228.083872)
		(width 0.18288)
		(layer "In6.Cu")
		(net "M_C_CPU1_SB_DQ<7>")
	)
	(segment
		(start 57.232804 -228.420168)
		(end 57.049924 -228.603048)
		(width 0.18288)
		(layer "In6.Cu")
		(net "M_C_CPU1_SB_DQ<7>")
	)
	(segment
		(start 53.19649 -228.49586)
		(end 53.19649 -228.243892)
		(width 0.18288)
		(layer "In6.Cu")
		(net "M_C_CPU1_SB_DQ<7>")
	)
	(segment
		(start 85.996526 -240.168938)
		(end 85.981794 -240.177574)
		(width 0.088646)
		(layer "In6.Cu")
		(net "M_C_CPU1_SB_DQ<7>")
	)
	(segment
		(start 72.672702 -238.299752)
		(end 67.04838 -232.67543)
		(width 0.18288)
		(layer "In6.Cu")
		(net "M_C_CPU1_SB_DQ<7>")
	)
	(segment
		(start 56.867044 -229.192836)
		(end 55.973472 -229.192836)
		(width 0.18288)
		(layer "In6.Cu")
		(net "M_C_CPU1_SB_DQ<7>")
	)
	(segment
		(start 54.58333 -228.49586)
		(end 54.58333 -227.974652)
		(width 0.18288)
		(layer "In6.Cu")
		(net "M_C_CPU1_SB_DQ<7>")
	)
	(segment
		(start 67.04838 -232.67543)
		(end 65.85839 -232.67543)
		(width 0.18288)
		(layer "In6.Cu")
		(net "M_C_CPU1_SB_DQ<7>")
	)
	(segment
		(start 82.835496 -238.299752)
		(end 72.672702 -238.299752)
		(width 0.18288)
		(layer "In6.Cu")
		(net "M_C_CPU1_SB_DQ<7>")
	)
	(segment
		(start 53.19649 -228.243892)
		(end 53.03647 -228.083872)
		(width 0.18288)
		(layer "In6.Cu")
		(net "M_C_CPU1_SB_DQ<7>")
	)
	(segment
		(start 87.495888 -240.1824)
		(end 87.487506 -240.177574)
		(width 0.088646)
		(layer "In6.Cu")
		(net "M_C_CPU1_SB_DQ<7>")
	)
	(segment
		(start 57.557924 -228.420168)
		(end 57.232804 -228.420168)
		(width 0.18288)
		(layer "In6.Cu")
		(net "M_C_CPU1_SB_DQ<7>")
	)
	(segment
		(start 52.66309 -228.083872)
		(end 52.50307 -228.243892)
		(width 0.18288)
		(layer "In6.Cu")
		(net "M_C_CPU1_SB_DQ<7>")
	)
	(segment
		(start 65.85839 -232.67543)
		(end 64.237616 -231.054656)
		(width 0.18288)
		(layer "In6.Cu")
		(net "M_C_CPU1_SB_DQ<7>")
	)
	(arc
		(start 91.247214 -240.177574)
		(mid 90.970655 -240.101865)
		(end 90.692478 -240.171478)
		(width 0.088646)
		(layer "In6.Cu")
		(net "M_C_CPU1_SB_DQ<7>")
	)
	(arc
		(start 88.80221 -240.177574)
		(mid 88.615012 -240.227717)
		(end 88.427814 -240.177574)
		(width 0.088646)
		(layer "In6.Cu")
		(net "M_C_CPU1_SB_DQ<7>")
	)
	(arc
		(start 94.44101 -240.177574)
		(mid 94.253812 -240.227717)
		(end 94.066614 -240.177574)
		(width 0.088646)
		(layer "In6.Cu")
		(net "M_C_CPU1_SB_DQ<7>")
	)
	(arc
		(start 90.297254 -240.171478)
		(mid 90.018822 -240.101664)
		(end 89.74201 -240.177574)
		(width 0.088646)
		(layer "In6.Cu")
		(net "M_C_CPU1_SB_DQ<7>")
	)
	(arc
		(start 92.172282 -240.168938)
		(mid 91.895841 -240.101772)
		(end 91.62161 -240.177574)
		(width 0.088646)
		(layer "In6.Cu")
		(net "M_C_CPU1_SB_DQ<7>")
	)
	(arc
		(start 86.547706 -240.177574)
		(mid 86.273253 -240.101646)
		(end 85.996526 -240.168938)
		(width 0.088646)
		(layer "In6.Cu")
		(net "M_C_CPU1_SB_DQ<7>")
	)
	(arc
		(start 89.74201 -240.177574)
		(mid 89.554812 -240.227717)
		(end 89.367614 -240.177574)
		(width 0.088646)
		(layer "In6.Cu")
		(net "M_C_CPU1_SB_DQ<7>")
	)
	(arc
		(start 86.907878 -240.185956)
		(mid 86.726715 -240.227896)
		(end 86.547706 -240.177574)
		(width 0.088646)
		(layer "In6.Cu")
		(net "M_C_CPU1_SB_DQ<7>")
	)
	(arc
		(start 85.607398 -240.177574)
		(mid 85.330585 -240.101738)
		(end 85.052154 -240.171478)
		(width 0.088646)
		(layer "In6.Cu")
		(net "M_C_CPU1_SB_DQ<7>")
	)
	(arc
		(start 90.682064 -240.177574)
		(mid 90.494866 -240.227717)
		(end 90.307668 -240.177574)
		(width 0.088646)
		(layer "In6.Cu")
		(net "M_C_CPU1_SB_DQ<7>")
	)
	(arc
		(start 94.051882 -240.168938)
		(mid 93.775441 -240.101772)
		(end 93.50121 -240.177574)
		(width 0.088646)
		(layer "In6.Cu")
		(net "M_C_CPU1_SB_DQ<7>")
	)
	(arc
		(start 93.50121 -240.177574)
		(mid 93.314012 -240.227717)
		(end 93.126814 -240.177574)
		(width 0.088646)
		(layer "In6.Cu")
		(net "M_C_CPU1_SB_DQ<7>")
	)
	(arc
		(start 93.112082 -240.168938)
		(mid 92.835641 -240.101772)
		(end 92.56141 -240.177574)
		(width 0.088646)
		(layer "In6.Cu")
		(net "M_C_CPU1_SB_DQ<7>")
	)
	(arc
		(start 89.352882 -240.168938)
		(mid 89.076441 -240.101772)
		(end 88.80221 -240.177574)
		(width 0.088646)
		(layer "In6.Cu")
		(net "M_C_CPU1_SB_DQ<7>")
	)
	(arc
		(start 95.38081 -240.177574)
		(mid 95.193612 -240.227717)
		(end 95.006414 -240.177574)
		(width 0.088646)
		(layer "In6.Cu")
		(net "M_C_CPU1_SB_DQ<7>")
	)
	(arc
		(start 92.56141 -240.177574)
		(mid 92.374212 -240.227717)
		(end 92.187014 -240.177574)
		(width 0.088646)
		(layer "In6.Cu")
		(net "M_C_CPU1_SB_DQ<7>")
	)
	(arc
		(start 84.667344 -240.177574)
		(mid 84.626286 -240.150687)
		(end 84.589112 -240.118646)
		(width 0.088646)
		(layer "In6.Cu")
		(net "M_C_CPU1_SB_DQ<7>")
	)
	(arc
		(start 96.22536 -240.601754)
		(mid 96.136116 -240.356532)
		(end 95.946214 -240.177574)
		(width 0.088646)
		(layer "In6.Cu")
		(net "M_C_CPU1_SB_DQ<7>")
	)
	(arc
		(start 87.862156 -240.177574)
		(mid 87.679651 -240.227812)
		(end 87.495888 -240.1824)
		(width 0.088646)
		(layer "In6.Cu")
		(net "M_C_CPU1_SB_DQ<7>")
	)
	(arc
		(start 91.62161 -240.177574)
		(mid 91.434412 -240.227717)
		(end 91.247214 -240.177574)
		(width 0.088646)
		(layer "In6.Cu")
		(net "M_C_CPU1_SB_DQ<7>")
	)
	(arc
		(start 85.04174 -240.177574)
		(mid 84.854542 -240.227717)
		(end 84.667344 -240.177574)
		(width 0.088646)
		(layer "In6.Cu")
		(net "M_C_CPU1_SB_DQ<7>")
	)
	(arc
		(start 88.40978 -240.16716)
		(mid 88.134622 -240.101667)
		(end 87.862156 -240.177574)
		(width 0.088646)
		(layer "In6.Cu")
		(net "M_C_CPU1_SB_DQ<7>")
	)
	(arc
		(start 94.991682 -240.168938)
		(mid 94.715241 -240.101772)
		(end 94.44101 -240.177574)
		(width 0.088646)
		(layer "In6.Cu")
		(net "M_C_CPU1_SB_DQ<7>")
	)
	(arc
		(start 85.981794 -240.177574)
		(mid 85.794596 -240.227717)
		(end 85.607398 -240.177574)
		(width 0.088646)
		(layer "In6.Cu")
		(net "M_C_CPU1_SB_DQ<7>")
	)
	(arc
		(start 87.487506 -240.177574)
		(mid 87.215294 -240.101807)
		(end 86.94039 -240.16716)
		(width 0.088646)
		(layer "In6.Cu")
		(net "M_C_CPU1_SB_DQ<7>")
	)
	(arc
		(start 95.931482 -240.168938)
		(mid 95.655041 -240.101772)
		(end 95.38081 -240.177574)
		(width 0.088646)
		(layer "In6.Cu")
		(net "M_C_CPU1_SB_DQ<7>")
	)
	(segment
		(start 27.328114 -225.36658)
		(end 28.475178 -225.36658)
		(width 0.20066)
		(layer "F.Cu")
		(net "M_C_CPU1_SB_DQ<6>")
	)
	(segment
		(start 35.976814 -225.36658)
		(end 34.871914 -225.36658)
		(width 0.20066)
		(layer "F.Cu")
		(net "M_C_CPU1_SB_DQ<6>")
	)
	(segment
		(start 97.073466 -242.017042)
		(end 97.073212 -242.016788)
		(width 0.20066)
		(layer "F.Cu")
		(net "M_C_CPU1_SB_DQ<6>")
	)
	(segment
		(start 32.605726 -224.941638)
		(end 32.74949 -225.085402)
		(width 0.20066)
		(layer "F.Cu")
		(net "M_C_CPU1_SB_DQ<6>")
	)
	(segment
		(start 31.972758 -224.941638)
		(end 32.605726 -224.941638)
		(width 0.20066)
		(layer "F.Cu")
		(net "M_C_CPU1_SB_DQ<6>")
	)
	(segment
		(start 29.657802 -224.941638)
		(end 29.912818 -224.941638)
		(width 0.101854)
		(layer "F.Cu")
		(net "M_C_CPU1_SB_DQ<6>")
	)
	(segment
		(start 28.475178 -225.36658)
		(end 28.91028 -224.931478)
		(width 0.20066)
		(layer "F.Cu")
		(net "M_C_CPU1_SB_DQ<6>")
	)
	(segment
		(start 32.74949 -225.085402)
		(end 32.74949 -225.41103)
		(width 0.20066)
		(layer "F.Cu")
		(net "M_C_CPU1_SB_DQ<6>")
	)
	(segment
		(start 29.912818 -224.941638)
		(end 31.972758 -224.941638)
		(width 0.1016)
		(layer "F.Cu")
		(net "M_C_CPU1_SB_DQ<6>")
	)
	(segment
		(start 29.647642 -224.931478)
		(end 29.657802 -224.941638)
		(width 0.101854)
		(layer "F.Cu")
		(net "M_C_CPU1_SB_DQ<6>")
	)
	(segment
		(start 32.74949 -225.41103)
		(end 32.916876 -225.578416)
		(width 0.20066)
		(layer "F.Cu")
		(net "M_C_CPU1_SB_DQ<6>")
	)
	(segment
		(start 33.345374 -225.578416)
		(end 33.55721 -225.36658)
		(width 0.20066)
		(layer "F.Cu")
		(net "M_C_CPU1_SB_DQ<6>")
	)
	(segment
		(start 28.91028 -224.931478)
		(end 29.647642 -224.931478)
		(width 0.20066)
		(layer "F.Cu")
		(net "M_C_CPU1_SB_DQ<6>")
	)
	(segment
		(start 32.916876 -225.578416)
		(end 33.345374 -225.578416)
		(width 0.20066)
		(layer "F.Cu")
		(net "M_C_CPU1_SB_DQ<6>")
	)
	(segment
		(start 97.073212 -242.016788)
		(end 97.073212 -241.481102)
		(width 0.20066)
		(layer "F.Cu")
		(net "M_C_CPU1_SB_DQ<6>")
	)
	(segment
		(start 33.55721 -225.36658)
		(end 34.871914 -225.36658)
		(width 0.20066)
		(layer "F.Cu")
		(net "M_C_CPU1_SB_DQ<6>")
	)
	(segment
		(start 49.831244 -230.041196)
		(end 49.671224 -229.881176)
		(width 0.18288)
		(layer "In6.Cu")
		(net "M_C_CPU1_SB_DQ<6>")
	)
	(segment
		(start 40.856662 -227.74275)
		(end 39.635176 -226.521264)
		(width 0.18288)
		(layer "In6.Cu")
		(net "M_C_CPU1_SB_DQ<6>")
	)
	(segment
		(start 38.96487 -226.521264)
		(end 38.42258 -225.978974)
		(width 0.18288)
		(layer "In6.Cu")
		(net "M_C_CPU1_SB_DQ<6>")
	)
	(segment
		(start 46.52518 -229.191566)
		(end 45.354494 -228.02088)
		(width 0.18288)
		(layer "In6.Cu")
		(net "M_C_CPU1_SB_DQ<6>")
	)
	(segment
		(start 36.589208 -225.978974)
		(end 35.976814 -225.36658)
		(width 0.18288)
		(layer "In6.Cu")
		(net "M_C_CPU1_SB_DQ<6>")
	)
	(segment
		(start 64.258698 -232.757472)
		(end 63.837566 -232.757472)
		(width 0.18288)
		(layer "In6.Cu")
		(net "M_C_CPU1_SB_DQ<6>")
	)
	(segment
		(start 49.511204 -229.422452)
		(end 49.137824 -229.422452)
		(width 0.18288)
		(layer "In6.Cu")
		(net "M_C_CPU1_SB_DQ<6>")
	)
	(segment
		(start 57.310782 -230.423466)
		(end 57.127902 -230.606346)
		(width 0.18288)
		(layer "In6.Cu")
		(net "M_C_CPU1_SB_DQ<6>")
	)
	(segment
		(start 48.977804 -229.582472)
		(end 48.977804 -229.881176)
		(width 0.18288)
		(layer "In6.Cu")
		(net "M_C_CPU1_SB_DQ<6>")
	)
	(segment
		(start 61.207142 -231.741472)
		(end 60.917836 -231.452166)
		(width 0.18288)
		(layer "In6.Cu")
		(net "M_C_CPU1_SB_DQ<6>")
	)
	(segment
		(start 43.913298 -228.306884)
		(end 42.983658 -228.306884)
		(width 0.18288)
		(layer "In6.Cu")
		(net "M_C_CPU1_SB_DQ<6>")
	)
	(segment
		(start 92.106496 -240.983008)
		(end 92.091764 -240.991644)
		(width 0.088646)
		(layer "In6.Cu")
		(net "M_C_CPU1_SB_DQ<6>")
	)
	(segment
		(start 57.127902 -230.936546)
		(end 56.945022 -231.119426)
		(width 0.18288)
		(layer "In6.Cu")
		(net "M_C_CPU1_SB_DQ<6>")
	)
	(segment
		(start 56.945022 -231.119426)
		(end 56.212232 -231.119426)
		(width 0.18288)
		(layer "In6.Cu")
		(net "M_C_CPU1_SB_DQ<6>")
	)
	(segment
		(start 57.818782 -230.936546)
		(end 57.818782 -230.606346)
		(width 0.18288)
		(layer "In6.Cu")
		(net "M_C_CPU1_SB_DQ<6>")
	)
	(segment
		(start 96.760538 -241.481102)
		(end 96.695006 -241.41557)
		(width 0.088646)
		(layer "In6.Cu")
		(net "M_C_CPU1_SB_DQ<6>")
	)
	(segment
		(start 57.635902 -230.423466)
		(end 57.310782 -230.423466)
		(width 0.18288)
		(layer "In6.Cu")
		(net "M_C_CPU1_SB_DQ<6>")
	)
	(segment
		(start 63.837566 -232.757472)
		(end 62.821566 -231.741472)
		(width 0.18288)
		(layer "In6.Cu")
		(net "M_C_CPU1_SB_DQ<6>")
	)
	(segment
		(start 57.818782 -230.606346)
		(end 57.635902 -230.423466)
		(width 0.18288)
		(layer "In6.Cu")
		(net "M_C_CPU1_SB_DQ<6>")
	)
	(segment
		(start 51.829208 -230.27005)
		(end 51.600354 -230.041196)
		(width 0.18288)
		(layer "In6.Cu")
		(net "M_C_CPU1_SB_DQ<6>")
	)
	(segment
		(start 55.362856 -230.27005)
		(end 53.989478 -230.27005)
		(width 0.18288)
		(layer "In6.Cu")
		(net "M_C_CPU1_SB_DQ<6>")
	)
	(segment
		(start 93.046296 -240.983008)
		(end 93.031564 -240.991644)
		(width 0.088646)
		(layer "In6.Cu")
		(net "M_C_CPU1_SB_DQ<6>")
	)
	(segment
		(start 38.42258 -225.978974)
		(end 36.589208 -225.978974)
		(width 0.18288)
		(layer "In6.Cu")
		(net "M_C_CPU1_SB_DQ<6>")
	)
	(segment
		(start 95.865696 -240.983008)
		(end 95.850964 -240.991644)
		(width 0.088646)
		(layer "In6.Cu")
		(net "M_C_CPU1_SB_DQ<6>")
	)
	(segment
		(start 97.073212 -241.481102)
		(end 96.760538 -241.481102)
		(width 0.088646)
		(layer "In6.Cu")
		(net "M_C_CPU1_SB_DQ<6>")
	)
	(segment
		(start 56.212232 -231.119426)
		(end 55.362856 -230.27005)
		(width 0.18288)
		(layer "In6.Cu")
		(net "M_C_CPU1_SB_DQ<6>")
	)
	(segment
		(start 84.656422 -240.915952)
		(end 83.783424 -240.042954)
		(width 0.088646)
		(layer "In6.Cu")
		(net "M_C_CPU1_SB_DQ<6>")
	)
	(segment
		(start 53.806598 -230.08717)
		(end 53.806598 -229.872032)
		(width 0.18288)
		(layer "In6.Cu")
		(net "M_C_CPU1_SB_DQ<6>")
	)
	(segment
		(start 39.635176 -226.521264)
		(end 38.96487 -226.521264)
		(width 0.18288)
		(layer "In6.Cu")
		(net "M_C_CPU1_SB_DQ<6>")
	)
	(segment
		(start 53.989478 -230.27005)
		(end 53.806598 -230.08717)
		(width 0.18288)
		(layer "In6.Cu")
		(net "M_C_CPU1_SB_DQ<6>")
	)
	(segment
		(start 60.539122 -231.452166)
		(end 60.249816 -231.741472)
		(width 0.18288)
		(layer "In6.Cu")
		(net "M_C_CPU1_SB_DQ<6>")
	)
	(segment
		(start 67.418204 -234.490514)
		(end 65.99174 -234.490514)
		(width 0.18288)
		(layer "In6.Cu")
		(net "M_C_CPU1_SB_DQ<6>")
	)
	(segment
		(start 83.783424 -239.820196)
		(end 83.70062 -239.620298)
		(width 0.088646)
		(layer "In6.Cu")
		(net "M_C_CPU1_SB_DQ<6>")
	)
	(segment
		(start 60.249816 -231.741472)
		(end 59.61126 -231.741472)
		(width 0.18288)
		(layer "In6.Cu")
		(net "M_C_CPU1_SB_DQ<6>")
	)
	(segment
		(start 83.386676 -239.306354)
		(end 83.089496 -239.306354)
		(width 0.088646)
		(layer "In6.Cu")
		(net "M_C_CPU1_SB_DQ<6>")
	)
	(segment
		(start 42.419524 -227.74275)
		(end 40.856662 -227.74275)
		(width 0.18288)
		(layer "In6.Cu")
		(net "M_C_CPU1_SB_DQ<6>")
	)
	(segment
		(start 48.476916 -230.041196)
		(end 47.627286 -229.191566)
		(width 0.18288)
		(layer "In6.Cu")
		(net "M_C_CPU1_SB_DQ<6>")
	)
	(segment
		(start 53.298598 -229.689152)
		(end 53.115718 -229.872032)
		(width 0.18288)
		(layer "In6.Cu")
		(net "M_C_CPU1_SB_DQ<6>")
	)
	(segment
		(start 84.856066 -240.915952)
		(end 84.656422 -240.915952)
		(width 0.088646)
		(layer "In6.Cu")
		(net "M_C_CPU1_SB_DQ<6>")
	)
	(segment
		(start 94.925896 -240.983008)
		(end 94.911164 -240.991644)
		(width 0.088646)
		(layer "In6.Cu")
		(net "M_C_CPU1_SB_DQ<6>")
	)
	(segment
		(start 53.623718 -229.689152)
		(end 53.298598 -229.689152)
		(width 0.18288)
		(layer "In6.Cu")
		(net "M_C_CPU1_SB_DQ<6>")
	)
	(segment
		(start 57.127902 -230.606346)
		(end 57.127902 -230.936546)
		(width 0.18288)
		(layer "In6.Cu")
		(net "M_C_CPU1_SB_DQ<6>")
	)
	(segment
		(start 48.817784 -230.041196)
		(end 48.476916 -230.041196)
		(width 0.18288)
		(layer "In6.Cu")
		(net "M_C_CPU1_SB_DQ<6>")
	)
	(segment
		(start 48.977804 -229.881176)
		(end 48.817784 -230.041196)
		(width 0.18288)
		(layer "In6.Cu")
		(net "M_C_CPU1_SB_DQ<6>")
	)
	(segment
		(start 44.223432 -228.617018)
		(end 43.913298 -228.306884)
		(width 0.18288)
		(layer "In6.Cu")
		(net "M_C_CPU1_SB_DQ<6>")
	)
	(segment
		(start 53.115718 -229.872032)
		(end 53.115718 -230.08717)
		(width 0.18288)
		(layer "In6.Cu")
		(net "M_C_CPU1_SB_DQ<6>")
	)
	(segment
		(start 53.115718 -230.08717)
		(end 52.932838 -230.27005)
		(width 0.18288)
		(layer "In6.Cu")
		(net "M_C_CPU1_SB_DQ<6>")
	)
	(segment
		(start 58.001662 -231.119426)
		(end 57.818782 -230.936546)
		(width 0.18288)
		(layer "In6.Cu")
		(net "M_C_CPU1_SB_DQ<6>")
	)
	(segment
		(start 83.783424 -240.042954)
		(end 83.783424 -239.820196)
		(width 0.088646)
		(layer "In6.Cu")
		(net "M_C_CPU1_SB_DQ<6>")
	)
	(segment
		(start 88.347296 -240.983008)
		(end 88.332564 -240.991644)
		(width 0.088646)
		(layer "In6.Cu")
		(net "M_C_CPU1_SB_DQ<6>")
	)
	(segment
		(start 42.983658 -228.306884)
		(end 42.419524 -227.74275)
		(width 0.18288)
		(layer "In6.Cu")
		(net "M_C_CPU1_SB_DQ<6>")
	)
	(segment
		(start 58.989214 -231.119426)
		(end 58.001662 -231.119426)
		(width 0.18288)
		(layer "In6.Cu")
		(net "M_C_CPU1_SB_DQ<6>")
	)
	(segment
		(start 89.287096 -240.983008)
		(end 89.272364 -240.991644)
		(width 0.088646)
		(layer "In6.Cu")
		(net "M_C_CPU1_SB_DQ<6>")
	)
	(segment
		(start 47.627286 -229.191566)
		(end 46.52518 -229.191566)
		(width 0.18288)
		(layer "In6.Cu")
		(net "M_C_CPU1_SB_DQ<6>")
	)
	(segment
		(start 49.671224 -229.582472)
		(end 49.511204 -229.422452)
		(width 0.18288)
		(layer "In6.Cu")
		(net "M_C_CPU1_SB_DQ<6>")
	)
	(segment
		(start 83.70062 -239.620298)
		(end 83.386676 -239.306354)
		(width 0.088646)
		(layer "In6.Cu")
		(net "M_C_CPU1_SB_DQ<6>")
	)
	(segment
		(start 44.862496 -228.02088)
		(end 44.702476 -228.1809)
		(width 0.18288)
		(layer "In6.Cu")
		(net "M_C_CPU1_SB_DQ<6>")
	)
	(segment
		(start 53.806598 -229.872032)
		(end 53.623718 -229.689152)
		(width 0.18288)
		(layer "In6.Cu")
		(net "M_C_CPU1_SB_DQ<6>")
	)
	(segment
		(start 44.702476 -228.1809)
		(end 44.702476 -228.456998)
		(width 0.18288)
		(layer "In6.Cu")
		(net "M_C_CPU1_SB_DQ<6>")
	)
	(segment
		(start 60.917836 -231.452166)
		(end 60.539122 -231.452166)
		(width 0.18288)
		(layer "In6.Cu")
		(net "M_C_CPU1_SB_DQ<6>")
	)
	(segment
		(start 72.234044 -239.306354)
		(end 67.418204 -234.490514)
		(width 0.18288)
		(layer "In6.Cu")
		(net "M_C_CPU1_SB_DQ<6>")
	)
	(segment
		(start 85.527896 -240.983008)
		(end 85.513164 -240.991644)
		(width 0.088646)
		(layer "In6.Cu")
		(net "M_C_CPU1_SB_DQ<6>")
	)
	(segment
		(start 59.61126 -231.741472)
		(end 58.989214 -231.119426)
		(width 0.18288)
		(layer "In6.Cu")
		(net "M_C_CPU1_SB_DQ<6>")
	)
	(segment
		(start 49.137824 -229.422452)
		(end 48.977804 -229.582472)
		(width 0.18288)
		(layer "In6.Cu")
		(net "M_C_CPU1_SB_DQ<6>")
	)
	(segment
		(start 45.354494 -228.02088)
		(end 44.862496 -228.02088)
		(width 0.18288)
		(layer "In6.Cu")
		(net "M_C_CPU1_SB_DQ<6>")
	)
	(segment
		(start 91.162124 -240.985548)
		(end 91.15171 -240.991644)
		(width 0.088646)
		(layer "In6.Cu")
		(net "M_C_CPU1_SB_DQ<6>")
	)
	(segment
		(start 65.99174 -234.490514)
		(end 64.258698 -232.757472)
		(width 0.18288)
		(layer "In6.Cu")
		(net "M_C_CPU1_SB_DQ<6>")
	)
	(segment
		(start 52.932838 -230.27005)
		(end 51.829208 -230.27005)
		(width 0.18288)
		(layer "In6.Cu")
		(net "M_C_CPU1_SB_DQ<6>")
	)
	(segment
		(start 51.600354 -230.041196)
		(end 49.831244 -230.041196)
		(width 0.18288)
		(layer "In6.Cu")
		(net "M_C_CPU1_SB_DQ<6>")
	)
	(segment
		(start 44.702476 -228.456998)
		(end 44.542456 -228.617018)
		(width 0.18288)
		(layer "In6.Cu")
		(net "M_C_CPU1_SB_DQ<6>")
	)
	(segment
		(start 49.671224 -229.881176)
		(end 49.671224 -229.582472)
		(width 0.18288)
		(layer "In6.Cu")
		(net "M_C_CPU1_SB_DQ<6>")
	)
	(segment
		(start 62.821566 -231.741472)
		(end 61.207142 -231.741472)
		(width 0.18288)
		(layer "In6.Cu")
		(net "M_C_CPU1_SB_DQ<6>")
	)
	(segment
		(start 83.089496 -239.306354)
		(end 72.234044 -239.306354)
		(width 0.18288)
		(layer "In6.Cu")
		(net "M_C_CPU1_SB_DQ<6>")
	)
	(segment
		(start 44.542456 -228.617018)
		(end 44.223432 -228.617018)
		(width 0.18288)
		(layer "In6.Cu")
		(net "M_C_CPU1_SB_DQ<6>")
	)
	(segment
		(start 90.222578 -240.985548)
		(end 90.212164 -240.991644)
		(width 0.088646)
		(layer "In6.Cu")
		(net "M_C_CPU1_SB_DQ<6>")
	)
	(arc
		(start 87.018368 -240.991644)
		(mid 86.735666 -240.915868)
		(end 86.452964 -240.991644)
		(width 0.088646)
		(layer "In6.Cu")
		(net "M_C_CPU1_SB_DQ<6>")
	)
	(arc
		(start 91.717368 -240.991644)
		(mid 91.440555 -240.915774)
		(end 91.162124 -240.985548)
		(width 0.088646)
		(layer "In6.Cu")
		(net "M_C_CPU1_SB_DQ<6>")
	)
	(arc
		(start 86.078568 -240.991644)
		(mid 85.804369 -240.915809)
		(end 85.527896 -240.983008)
		(width 0.088646)
		(layer "In6.Cu")
		(net "M_C_CPU1_SB_DQ<6>")
	)
	(arc
		(start 93.596968 -240.991644)
		(mid 93.322769 -240.915809)
		(end 93.046296 -240.983008)
		(width 0.088646)
		(layer "In6.Cu")
		(net "M_C_CPU1_SB_DQ<6>")
	)
	(arc
		(start 87.392764 -240.991644)
		(mid 87.205566 -241.041787)
		(end 87.018368 -240.991644)
		(width 0.088646)
		(layer "In6.Cu")
		(net "M_C_CPU1_SB_DQ<6>")
	)
	(arc
		(start 85.513164 -240.991644)
		(mid 85.325966 -241.041787)
		(end 85.138768 -240.991644)
		(width 0.088646)
		(layer "In6.Cu")
		(net "M_C_CPU1_SB_DQ<6>")
	)
	(arc
		(start 94.536768 -240.991644)
		(mid 94.254066 -240.915868)
		(end 93.971364 -240.991644)
		(width 0.088646)
		(layer "In6.Cu")
		(net "M_C_CPU1_SB_DQ<6>")
	)
	(arc
		(start 93.031564 -240.991644)
		(mid 92.844366 -241.041787)
		(end 92.657168 -240.991644)
		(width 0.088646)
		(layer "In6.Cu")
		(net "M_C_CPU1_SB_DQ<6>")
	)
	(arc
		(start 92.091764 -240.991644)
		(mid 91.904566 -241.041787)
		(end 91.717368 -240.991644)
		(width 0.088646)
		(layer "In6.Cu")
		(net "M_C_CPU1_SB_DQ<6>")
	)
	(arc
		(start 90.212164 -240.991644)
		(mid 90.024966 -241.041787)
		(end 89.837768 -240.991644)
		(width 0.088646)
		(layer "In6.Cu")
		(net "M_C_CPU1_SB_DQ<6>")
	)
	(arc
		(start 92.657168 -240.991644)
		(mid 92.382969 -240.915809)
		(end 92.106496 -240.983008)
		(width 0.088646)
		(layer "In6.Cu")
		(net "M_C_CPU1_SB_DQ<6>")
	)
	(arc
		(start 96.416368 -240.991644)
		(mid 96.142169 -240.915809)
		(end 95.865696 -240.983008)
		(width 0.088646)
		(layer "In6.Cu")
		(net "M_C_CPU1_SB_DQ<6>")
	)
	(arc
		(start 88.897968 -240.991644)
		(mid 88.623769 -240.915809)
		(end 88.347296 -240.983008)
		(width 0.088646)
		(layer "In6.Cu")
		(net "M_C_CPU1_SB_DQ<6>")
	)
	(arc
		(start 90.777314 -240.991644)
		(mid 90.500755 -240.915901)
		(end 90.222578 -240.985548)
		(width 0.088646)
		(layer "In6.Cu")
		(net "M_C_CPU1_SB_DQ<6>")
	)
	(arc
		(start 95.850964 -240.991644)
		(mid 95.663766 -241.041787)
		(end 95.476568 -240.991644)
		(width 0.088646)
		(layer "In6.Cu")
		(net "M_C_CPU1_SB_DQ<6>")
	)
	(arc
		(start 85.138768 -240.991644)
		(mid 85.002402 -240.935166)
		(end 84.856066 -240.915952)
		(width 0.088646)
		(layer "In6.Cu")
		(net "M_C_CPU1_SB_DQ<6>")
	)
	(arc
		(start 89.272364 -240.991644)
		(mid 89.085166 -241.041787)
		(end 88.897968 -240.991644)
		(width 0.088646)
		(layer "In6.Cu")
		(net "M_C_CPU1_SB_DQ<6>")
	)
	(arc
		(start 96.695006 -241.41557)
		(mid 96.605918 -241.170585)
		(end 96.416368 -240.991644)
		(width 0.088646)
		(layer "In6.Cu")
		(net "M_C_CPU1_SB_DQ<6>")
	)
	(arc
		(start 93.971364 -240.991644)
		(mid 93.784166 -241.041787)
		(end 93.596968 -240.991644)
		(width 0.088646)
		(layer "In6.Cu")
		(net "M_C_CPU1_SB_DQ<6>")
	)
	(arc
		(start 94.911164 -240.991644)
		(mid 94.723966 -241.041787)
		(end 94.536768 -240.991644)
		(width 0.088646)
		(layer "In6.Cu")
		(net "M_C_CPU1_SB_DQ<6>")
	)
	(arc
		(start 87.958168 -240.991644)
		(mid 87.675466 -240.915868)
		(end 87.392764 -240.991644)
		(width 0.088646)
		(layer "In6.Cu")
		(net "M_C_CPU1_SB_DQ<6>")
	)
	(arc
		(start 91.15171 -240.991644)
		(mid 90.964512 -241.041787)
		(end 90.777314 -240.991644)
		(width 0.088646)
		(layer "In6.Cu")
		(net "M_C_CPU1_SB_DQ<6>")
	)
	(arc
		(start 95.476568 -240.991644)
		(mid 95.202369 -240.915809)
		(end 94.925896 -240.983008)
		(width 0.088646)
		(layer "In6.Cu")
		(net "M_C_CPU1_SB_DQ<6>")
	)
	(arc
		(start 89.837768 -240.991644)
		(mid 89.563569 -240.915809)
		(end 89.287096 -240.983008)
		(width 0.088646)
		(layer "In6.Cu")
		(net "M_C_CPU1_SB_DQ<6>")
	)
	(arc
		(start 86.452964 -240.991644)
		(mid 86.265766 -241.041787)
		(end 86.078568 -240.991644)
		(width 0.088646)
		(layer "In6.Cu")
		(net "M_C_CPU1_SB_DQ<6>")
	)
	(arc
		(start 88.332564 -240.991644)
		(mid 88.145366 -241.041787)
		(end 87.958168 -240.991644)
		(width 0.088646)
		(layer "In6.Cu")
		(net "M_C_CPU1_SB_DQ<6>")
	)
	(segment
		(start 29.13253 -224.516696)
		(end 30.771846 -224.516696)
		(width 0.20066)
		(layer "F.Cu")
		(net "M_C_CPU1_SB_DQ<5>")
	)
	(segment
		(start 25.595072 -224.082864)
		(end 26.20391 -224.082864)
		(width 0.20066)
		(layer "F.Cu")
		(net "M_C_CPU1_SB_DQ<5>")
	)
	(segment
		(start 28.707588 -224.091754)
		(end 29.13253 -224.516696)
		(width 0.20066)
		(layer "F.Cu")
		(net "M_C_CPU1_SB_DQ<5>")
	)
	(segment
		(start 95.663512 -241.203226)
		(end 95.663766 -241.202972)
		(width 0.20066)
		(layer "F.Cu")
		(net "M_C_CPU1_SB_DQ<5>")
	)
	(segment
		(start 31.876746 -224.516696)
		(end 30.771846 -224.516696)
		(width 0.20066)
		(layer "F.Cu")
		(net "M_C_CPU1_SB_DQ<5>")
	)
	(segment
		(start 25.27808 -224.728024)
		(end 25.432512 -224.573592)
		(width 0.20066)
		(layer "F.Cu")
		(net "M_C_CPU1_SB_DQ<5>")
	)
	(segment
		(start 26.2128 -224.091754)
		(end 28.198318 -224.091754)
		(width 0.1016)
		(layer "F.Cu")
		(net "M_C_CPU1_SB_DQ<5>")
	)
	(segment
		(start 26.20391 -224.082864)
		(end 26.2128 -224.091754)
		(width 0.1016)
		(layer "F.Cu")
		(net "M_C_CPU1_SB_DQ<5>")
	)
	(segment
		(start 28.198318 -224.091754)
		(end 28.529026 -224.091754)
		(width 0.101854)
		(layer "F.Cu")
		(net "M_C_CPU1_SB_DQ<5>")
	)
	(segment
		(start 28.529026 -224.091754)
		(end 28.707588 -224.091754)
		(width 0.20066)
		(layer "F.Cu")
		(net "M_C_CPU1_SB_DQ<5>")
	)
	(segment
		(start 95.663766 -241.202972)
		(end 95.663766 -240.667286)
		(width 0.20066)
		(layer "F.Cu")
		(net "M_C_CPU1_SB_DQ<5>")
	)
	(segment
		(start 24.773636 -224.728024)
		(end 25.27808 -224.728024)
		(width 0.20066)
		(layer "F.Cu")
		(net "M_C_CPU1_SB_DQ<5>")
	)
	(segment
		(start 23.228046 -224.516696)
		(end 24.562308 -224.516696)
		(width 0.20066)
		(layer "F.Cu")
		(net "M_C_CPU1_SB_DQ<5>")
	)
	(segment
		(start 24.562308 -224.516696)
		(end 24.773636 -224.728024)
		(width 0.20066)
		(layer "F.Cu")
		(net "M_C_CPU1_SB_DQ<5>")
	)
	(segment
		(start 25.432512 -224.245424)
		(end 25.595072 -224.082864)
		(width 0.20066)
		(layer "F.Cu")
		(net "M_C_CPU1_SB_DQ<5>")
	)
	(segment
		(start 25.432512 -224.573592)
		(end 25.432512 -224.245424)
		(width 0.20066)
		(layer "F.Cu")
		(net "M_C_CPU1_SB_DQ<5>")
	)
	(segment
		(start 55.214266 -229.191312)
		(end 50.235612 -229.191312)
		(width 0.18288)
		(layer "In6.Cu")
		(net "M_C_CPU1_SB_DQ<5>")
	)
	(segment
		(start 55.94858 -229.925626)
		(end 55.214266 -229.191312)
		(width 0.18288)
		(layer "In6.Cu")
		(net "M_C_CPU1_SB_DQ<5>")
	)
	(segment
		(start 94.925896 -240.351564)
		(end 94.911164 -240.342928)
		(width 0.088646)
		(layer "In6.Cu")
		(net "M_C_CPU1_SB_DQ<5>")
	)
	(segment
		(start 65.737994 -233.28884)
		(end 64.06261 -231.613456)
		(width 0.18288)
		(layer "In6.Cu")
		(net "M_C_CPU1_SB_DQ<5>")
	)
	(segment
		(start 87.017606 -240.342928)
		(end 86.996778 -240.35512)
		(width 0.088646)
		(layer "In6.Cu")
		(net "M_C_CPU1_SB_DQ<5>")
	)
	(segment
		(start 84.454492 -240.253266)
		(end 84.021676 -239.82045)
		(width 0.088646)
		(layer "In6.Cu")
		(net "M_C_CPU1_SB_DQ<5>")
	)
	(segment
		(start 41.052496 -227.21316)
		(end 39.839646 -226.00031)
		(width 0.18288)
		(layer "In6.Cu")
		(net "M_C_CPU1_SB_DQ<5>")
	)
	(segment
		(start 38.615874 -225.415856)
		(end 37.971476 -225.415856)
		(width 0.18288)
		(layer "In6.Cu")
		(net "M_C_CPU1_SB_DQ<5>")
	)
	(segment
		(start 85.137244 -240.342928)
		(end 85.12683 -240.349024)
		(width 0.088646)
		(layer "In6.Cu")
		(net "M_C_CPU1_SB_DQ<5>")
	)
	(segment
		(start 64.06261 -231.613456)
		(end 63.547752 -231.613456)
		(width 0.18288)
		(layer "In6.Cu")
		(net "M_C_CPU1_SB_DQ<5>")
	)
	(segment
		(start 32.301434 -224.941384)
		(end 31.876746 -224.516696)
		(width 0.18288)
		(layer "In6.Cu")
		(net "M_C_CPU1_SB_DQ<5>")
	)
	(segment
		(start 91.162124 -240.349024)
		(end 91.15171 -240.342928)
		(width 0.088646)
		(layer "In6.Cu")
		(net "M_C_CPU1_SB_DQ<5>")
	)
	(segment
		(start 37.971476 -225.415856)
		(end 37.497004 -224.941384)
		(width 0.18288)
		(layer "In6.Cu")
		(net "M_C_CPU1_SB_DQ<5>")
	)
	(segment
		(start 87.025988 -240.338102)
		(end 87.017606 -240.342928)
		(width 0.088646)
		(layer "In6.Cu")
		(net "M_C_CPU1_SB_DQ<5>")
	)
	(segment
		(start 89.287096 -240.351564)
		(end 89.272364 -240.342928)
		(width 0.088646)
		(layer "In6.Cu")
		(net "M_C_CPU1_SB_DQ<5>")
	)
	(segment
		(start 86.089236 -240.33607)
		(end 86.077298 -240.342928)
		(width 0.088646)
		(layer "In6.Cu")
		(net "M_C_CPU1_SB_DQ<5>")
	)
	(segment
		(start 48.53559 -227.49129)
		(end 43.19143 -227.49129)
		(width 0.18288)
		(layer "In6.Cu")
		(net "M_C_CPU1_SB_DQ<5>")
	)
	(segment
		(start 72.46493 -238.801148)
		(end 66.952622 -233.28884)
		(width 0.18288)
		(layer "In6.Cu")
		(net "M_C_CPU1_SB_DQ<5>")
	)
	(segment
		(start 62.825884 -230.891588)
		(end 60.409328 -230.891588)
		(width 0.18288)
		(layer "In6.Cu")
		(net "M_C_CPU1_SB_DQ<5>")
	)
	(segment
		(start 43.19143 -227.49129)
		(end 42.9133 -227.21316)
		(width 0.18288)
		(layer "In6.Cu")
		(net "M_C_CPU1_SB_DQ<5>")
	)
	(segment
		(start 95.663766 -240.667286)
		(end 95.97644 -240.667286)
		(width 0.088646)
		(layer "In6.Cu")
		(net "M_C_CPU1_SB_DQ<5>")
	)
	(segment
		(start 60.409328 -230.891588)
		(end 59.443366 -229.925626)
		(width 0.18288)
		(layer "In6.Cu")
		(net "M_C_CPU1_SB_DQ<5>")
	)
	(segment
		(start 50.235612 -229.191312)
		(end 48.53559 -227.49129)
		(width 0.18288)
		(layer "In6.Cu")
		(net "M_C_CPU1_SB_DQ<5>")
	)
	(segment
		(start 37.497004 -224.941384)
		(end 32.301434 -224.941384)
		(width 0.18288)
		(layer "In6.Cu")
		(net "M_C_CPU1_SB_DQ<5>")
	)
	(segment
		(start 90.777314 -240.342928)
		(end 90.7669 -240.349024)
		(width 0.088646)
		(layer "In6.Cu")
		(net "M_C_CPU1_SB_DQ<5>")
	)
	(segment
		(start 83.277964 -238.801148)
		(end 83.089496 -238.801148)
		(width 0.088646)
		(layer "In6.Cu")
		(net "M_C_CPU1_SB_DQ<5>")
	)
	(segment
		(start 63.547752 -231.613456)
		(end 62.825884 -230.891588)
		(width 0.18288)
		(layer "In6.Cu")
		(net "M_C_CPU1_SB_DQ<5>")
	)
	(segment
		(start 88.332564 -240.342928)
		(end 88.324182 -240.338102)
		(width 0.088646)
		(layer "In6.Cu")
		(net "M_C_CPU1_SB_DQ<5>")
	)
	(segment
		(start 83.826604 -239.349788)
		(end 83.277964 -238.801148)
		(width 0.088646)
		(layer "In6.Cu")
		(net "M_C_CPU1_SB_DQ<5>")
	)
	(segment
		(start 42.9133 -227.21316)
		(end 41.052496 -227.21316)
		(width 0.18288)
		(layer "In6.Cu")
		(net "M_C_CPU1_SB_DQ<5>")
	)
	(segment
		(start 95.859854 -240.348008)
		(end 95.850964 -240.342928)
		(width 0.088646)
		(layer "In6.Cu")
		(net "M_C_CPU1_SB_DQ<5>")
	)
	(segment
		(start 86.077298 -240.342928)
		(end 86.066884 -240.349024)
		(width 0.088646)
		(layer "In6.Cu")
		(net "M_C_CPU1_SB_DQ<5>")
	)
	(segment
		(start 93.046296 -240.351564)
		(end 93.031564 -240.342928)
		(width 0.088646)
		(layer "In6.Cu")
		(net "M_C_CPU1_SB_DQ<5>")
	)
	(segment
		(start 93.986096 -240.351564)
		(end 93.971364 -240.342928)
		(width 0.088646)
		(layer "In6.Cu")
		(net "M_C_CPU1_SB_DQ<5>")
	)
	(segment
		(start 87.402162 -240.349024)
		(end 87.391748 -240.342928)
		(width 0.088646)
		(layer "In6.Cu")
		(net "M_C_CPU1_SB_DQ<5>")
	)
	(segment
		(start 95.97644 -240.667286)
		(end 96.033844 -240.609882)
		(width 0.088646)
		(layer "In6.Cu")
		(net "M_C_CPU1_SB_DQ<5>")
	)
	(segment
		(start 88.347296 -240.351564)
		(end 88.332564 -240.342928)
		(width 0.088646)
		(layer "In6.Cu")
		(net "M_C_CPU1_SB_DQ<5>")
	)
	(segment
		(start 84.021676 -239.82045)
		(end 83.826604 -239.349788)
		(width 0.088646)
		(layer "In6.Cu")
		(net "M_C_CPU1_SB_DQ<5>")
	)
	(segment
		(start 59.443366 -229.925626)
		(end 55.94858 -229.925626)
		(width 0.18288)
		(layer "In6.Cu")
		(net "M_C_CPU1_SB_DQ<5>")
	)
	(segment
		(start 39.200328 -226.00031)
		(end 38.615874 -225.415856)
		(width 0.18288)
		(layer "In6.Cu")
		(net "M_C_CPU1_SB_DQ<5>")
	)
	(segment
		(start 83.089496 -238.801148)
		(end 72.46493 -238.801148)
		(width 0.18288)
		(layer "In6.Cu")
		(net "M_C_CPU1_SB_DQ<5>")
	)
	(segment
		(start 66.952622 -233.28884)
		(end 65.737994 -233.28884)
		(width 0.18288)
		(layer "In6.Cu")
		(net "M_C_CPU1_SB_DQ<5>")
	)
	(segment
		(start 92.106496 -240.351564)
		(end 92.091764 -240.342928)
		(width 0.088646)
		(layer "In6.Cu")
		(net "M_C_CPU1_SB_DQ<5>")
	)
	(segment
		(start 39.839646 -226.00031)
		(end 39.200328 -226.00031)
		(width 0.18288)
		(layer "In6.Cu")
		(net "M_C_CPU1_SB_DQ<5>")
	)
	(arc
		(start 91.717368 -240.342928)
		(mid 91.440555 -240.418764)
		(end 91.162124 -240.349024)
		(width 0.088646)
		(layer "In6.Cu")
		(net "M_C_CPU1_SB_DQ<5>")
	)
	(arc
		(start 86.996778 -240.35512)
		(mid 86.722936 -240.418835)
		(end 86.452202 -240.342928)
		(width 0.088646)
		(layer "In6.Cu")
		(net "M_C_CPU1_SB_DQ<5>")
	)
	(arc
		(start 84.571586 -240.342928)
		(mid 84.510101 -240.301933)
		(end 84.454492 -240.253266)
		(width 0.088646)
		(layer "In6.Cu")
		(net "M_C_CPU1_SB_DQ<5>")
	)
	(arc
		(start 87.391748 -240.342928)
		(mid 87.209497 -240.292817)
		(end 87.025988 -240.338102)
		(width 0.088646)
		(layer "In6.Cu")
		(net "M_C_CPU1_SB_DQ<5>")
	)
	(arc
		(start 93.031564 -240.342928)
		(mid 92.844366 -240.292785)
		(end 92.657168 -240.342928)
		(width 0.088646)
		(layer "In6.Cu")
		(net "M_C_CPU1_SB_DQ<5>")
	)
	(arc
		(start 87.957914 -240.342928)
		(mid 87.680847 -240.418891)
		(end 87.402162 -240.349024)
		(width 0.088646)
		(layer "In6.Cu")
		(net "M_C_CPU1_SB_DQ<5>")
	)
	(arc
		(start 88.324182 -240.338102)
		(mid 88.14042 -240.292702)
		(end 87.957914 -240.342928)
		(width 0.088646)
		(layer "In6.Cu")
		(net "M_C_CPU1_SB_DQ<5>")
	)
	(arc
		(start 96.033844 -240.609882)
		(mid 95.975688 -240.459769)
		(end 95.859854 -240.348008)
		(width 0.088646)
		(layer "In6.Cu")
		(net "M_C_CPU1_SB_DQ<5>")
	)
	(arc
		(start 88.897968 -240.342928)
		(mid 88.623739 -240.418853)
		(end 88.347296 -240.351564)
		(width 0.088646)
		(layer "In6.Cu")
		(net "M_C_CPU1_SB_DQ<5>")
	)
	(arc
		(start 93.971364 -240.342928)
		(mid 93.784166 -240.292785)
		(end 93.596968 -240.342928)
		(width 0.088646)
		(layer "In6.Cu")
		(net "M_C_CPU1_SB_DQ<5>")
	)
	(arc
		(start 94.911164 -240.342928)
		(mid 94.723966 -240.292785)
		(end 94.536768 -240.342928)
		(width 0.088646)
		(layer "In6.Cu")
		(net "M_C_CPU1_SB_DQ<5>")
	)
	(arc
		(start 95.476568 -240.342928)
		(mid 95.202339 -240.418853)
		(end 94.925896 -240.351564)
		(width 0.088646)
		(layer "In6.Cu")
		(net "M_C_CPU1_SB_DQ<5>")
	)
	(arc
		(start 89.837768 -240.342928)
		(mid 89.563539 -240.418853)
		(end 89.287096 -240.351564)
		(width 0.088646)
		(layer "In6.Cu")
		(net "M_C_CPU1_SB_DQ<5>")
	)
	(arc
		(start 91.15171 -240.342928)
		(mid 90.964512 -240.292785)
		(end 90.777314 -240.342928)
		(width 0.088646)
		(layer "In6.Cu")
		(net "M_C_CPU1_SB_DQ<5>")
	)
	(arc
		(start 94.536768 -240.342928)
		(mid 94.262539 -240.418853)
		(end 93.986096 -240.351564)
		(width 0.088646)
		(layer "In6.Cu")
		(net "M_C_CPU1_SB_DQ<5>")
	)
	(arc
		(start 86.066884 -240.349024)
		(mid 85.788452 -240.418838)
		(end 85.51164 -240.342928)
		(width 0.088646)
		(layer "In6.Cu")
		(net "M_C_CPU1_SB_DQ<5>")
	)
	(arc
		(start 93.596968 -240.342928)
		(mid 93.322739 -240.418853)
		(end 93.046296 -240.351564)
		(width 0.088646)
		(layer "In6.Cu")
		(net "M_C_CPU1_SB_DQ<5>")
	)
	(arc
		(start 90.212164 -240.342928)
		(mid 90.024966 -240.292785)
		(end 89.837768 -240.342928)
		(width 0.088646)
		(layer "In6.Cu")
		(net "M_C_CPU1_SB_DQ<5>")
	)
	(arc
		(start 85.12683 -240.349024)
		(mid 84.848398 -240.418838)
		(end 84.571586 -240.342928)
		(width 0.088646)
		(layer "In6.Cu")
		(net "M_C_CPU1_SB_DQ<5>")
	)
	(arc
		(start 95.850964 -240.342928)
		(mid 95.663766 -240.292785)
		(end 95.476568 -240.342928)
		(width 0.088646)
		(layer "In6.Cu")
		(net "M_C_CPU1_SB_DQ<5>")
	)
	(arc
		(start 92.091764 -240.342928)
		(mid 91.904566 -240.292785)
		(end 91.717368 -240.342928)
		(width 0.088646)
		(layer "In6.Cu")
		(net "M_C_CPU1_SB_DQ<5>")
	)
	(arc
		(start 89.272364 -240.342928)
		(mid 89.085166 -240.292785)
		(end 88.897968 -240.342928)
		(width 0.088646)
		(layer "In6.Cu")
		(net "M_C_CPU1_SB_DQ<5>")
	)
	(arc
		(start 92.657168 -240.342928)
		(mid 92.382939 -240.418853)
		(end 92.106496 -240.351564)
		(width 0.088646)
		(layer "In6.Cu")
		(net "M_C_CPU1_SB_DQ<5>")
	)
	(arc
		(start 85.51164 -240.342928)
		(mid 85.324442 -240.292785)
		(end 85.137244 -240.342928)
		(width 0.088646)
		(layer "In6.Cu")
		(net "M_C_CPU1_SB_DQ<5>")
	)
	(arc
		(start 90.7669 -240.349024)
		(mid 90.488722 -240.418716)
		(end 90.212164 -240.342928)
		(width 0.088646)
		(layer "In6.Cu")
		(net "M_C_CPU1_SB_DQ<5>")
	)
	(arc
		(start 86.452202 -240.342928)
		(mid 86.271601 -240.292598)
		(end 86.089236 -240.33607)
		(width 0.088646)
		(layer "In6.Cu")
		(net "M_C_CPU1_SB_DQ<5>")
	)
	(segment
		(start 95.193612 -242.016788)
		(end 95.193612 -241.481102)
		(width 0.20066)
		(layer "F.Cu")
		(net "M_C_CPU1_SB_DQ<4>")
	)
	(segment
		(start 25.432512 -225.993198)
		(end 25.642062 -225.783648)
		(width 0.20066)
		(layer "F.Cu")
		(net "M_C_CPU1_SB_DQ<4>")
	)
	(segment
		(start 25.642062 -225.783648)
		(end 26.20391 -225.783648)
		(width 0.20066)
		(layer "F.Cu")
		(net "M_C_CPU1_SB_DQ<4>")
	)
	(segment
		(start 24.801068 -226.455478)
		(end 25.259792 -226.455478)
		(width 0.20066)
		(layer "F.Cu")
		(net "M_C_CPU1_SB_DQ<4>")
	)
	(segment
		(start 95.193866 -242.017042)
		(end 95.193612 -242.016788)
		(width 0.20066)
		(layer "F.Cu")
		(net "M_C_CPU1_SB_DQ<4>")
	)
	(segment
		(start 28.529026 -225.791776)
		(end 28.977844 -225.791776)
		(width 0.20066)
		(layer "F.Cu")
		(net "M_C_CPU1_SB_DQ<4>")
	)
	(segment
		(start 25.432512 -226.282758)
		(end 25.432512 -225.993198)
		(width 0.20066)
		(layer "F.Cu")
		(net "M_C_CPU1_SB_DQ<4>")
	)
	(segment
		(start 26.20391 -225.783648)
		(end 26.212038 -225.791776)
		(width 0.101854)
		(layer "F.Cu")
		(net "M_C_CPU1_SB_DQ<4>")
	)
	(segment
		(start 31.876746 -226.216718)
		(end 30.771846 -226.216718)
		(width 0.20066)
		(layer "F.Cu")
		(net "M_C_CPU1_SB_DQ<4>")
	)
	(segment
		(start 28.977844 -225.791776)
		(end 29.402786 -226.216718)
		(width 0.20066)
		(layer "F.Cu")
		(net "M_C_CPU1_SB_DQ<4>")
	)
	(segment
		(start 24.562308 -226.216718)
		(end 24.801068 -226.455478)
		(width 0.20066)
		(layer "F.Cu")
		(net "M_C_CPU1_SB_DQ<4>")
	)
	(segment
		(start 26.459942 -225.791776)
		(end 28.529026 -225.791776)
		(width 0.1016)
		(layer "F.Cu")
		(net "M_C_CPU1_SB_DQ<4>")
	)
	(segment
		(start 29.402786 -226.216718)
		(end 30.771846 -226.216718)
		(width 0.20066)
		(layer "F.Cu")
		(net "M_C_CPU1_SB_DQ<4>")
	)
	(segment
		(start 25.259792 -226.455478)
		(end 25.432512 -226.282758)
		(width 0.20066)
		(layer "F.Cu")
		(net "M_C_CPU1_SB_DQ<4>")
	)
	(segment
		(start 23.228046 -226.216718)
		(end 24.562308 -226.216718)
		(width 0.20066)
		(layer "F.Cu")
		(net "M_C_CPU1_SB_DQ<4>")
	)
	(segment
		(start 26.212038 -225.791776)
		(end 26.459942 -225.791776)
		(width 0.101854)
		(layer "F.Cu")
		(net "M_C_CPU1_SB_DQ<4>")
	)
	(segment
		(start 65.79743 -235.005372)
		(end 64.165226 -233.373168)
		(width 0.18288)
		(layer "In6.Cu")
		(net "M_C_CPU1_SB_DQ<4>")
	)
	(segment
		(start 42.50436 -229.192328)
		(end 41.631362 -228.31933)
		(width 0.18288)
		(layer "In6.Cu")
		(net "M_C_CPU1_SB_DQ<4>")
	)
	(segment
		(start 34.556446 -227.065078)
		(end 34.556446 -226.823778)
		(width 0.18288)
		(layer "In6.Cu")
		(net "M_C_CPU1_SB_DQ<4>")
	)
	(segment
		(start 45.825156 -230.041704)
		(end 44.97578 -229.192328)
		(width 0.18288)
		(layer "In6.Cu")
		(net "M_C_CPU1_SB_DQ<4>")
	)
	(segment
		(start 33.865566 -227.065078)
		(end 33.682686 -227.247958)
		(width 0.18288)
		(layer "In6.Cu")
		(net "M_C_CPU1_SB_DQ<4>")
	)
	(segment
		(start 34.556446 -226.823778)
		(end 34.373566 -226.640898)
		(width 0.18288)
		(layer "In6.Cu")
		(net "M_C_CPU1_SB_DQ<4>")
	)
	(segment
		(start 34.739326 -227.247958)
		(end 34.556446 -227.065078)
		(width 0.18288)
		(layer "In6.Cu")
		(net "M_C_CPU1_SB_DQ<4>")
	)
	(segment
		(start 93.126814 -241.156744)
		(end 93.112082 -241.16538)
		(width 0.088646)
		(layer "In6.Cu")
		(net "M_C_CPU1_SB_DQ<4>")
	)
	(segment
		(start 92.187014 -241.156744)
		(end 92.172282 -241.16538)
		(width 0.088646)
		(layer "In6.Cu")
		(net "M_C_CPU1_SB_DQ<4>")
	)
	(segment
		(start 84.577428 -241.106198)
		(end 83.570064 -240.098834)
		(width 0.088646)
		(layer "In6.Cu")
		(net "M_C_CPU1_SB_DQ<4>")
	)
	(segment
		(start 33.357566 -227.247958)
		(end 33.174686 -227.065078)
		(width 0.18288)
		(layer "In6.Cu")
		(net "M_C_CPU1_SB_DQ<4>")
	)
	(segment
		(start 47.766478 -230.041704)
		(end 45.825156 -230.041704)
		(width 0.18288)
		(layer "In6.Cu")
		(net "M_C_CPU1_SB_DQ<4>")
	)
	(segment
		(start 85.608414 -241.156744)
		(end 85.593682 -241.16538)
		(width 0.088646)
		(layer "In6.Cu")
		(net "M_C_CPU1_SB_DQ<4>")
	)
	(segment
		(start 58.79211 -231.652826)
		(end 55.785766 -231.652826)
		(width 0.18288)
		(layer "In6.Cu")
		(net "M_C_CPU1_SB_DQ<4>")
	)
	(segment
		(start 34.373566 -226.640898)
		(end 34.048446 -226.640898)
		(width 0.18288)
		(layer "In6.Cu")
		(net "M_C_CPU1_SB_DQ<4>")
	)
	(segment
		(start 88.427814 -241.156744)
		(end 88.4174 -241.16284)
		(width 0.088646)
		(layer "In6.Cu")
		(net "M_C_CPU1_SB_DQ<4>")
	)
	(segment
		(start 67.226688 -235.005372)
		(end 65.79743 -235.005372)
		(width 0.18288)
		(layer "In6.Cu")
		(net "M_C_CPU1_SB_DQ<4>")
	)
	(segment
		(start 84.856066 -241.106198)
		(end 84.577428 -241.106198)
		(width 0.088646)
		(layer "In6.Cu")
		(net "M_C_CPU1_SB_DQ<4>")
	)
	(segment
		(start 33.174686 -227.065078)
		(end 33.174686 -226.823778)
		(width 0.18288)
		(layer "In6.Cu")
		(net "M_C_CPU1_SB_DQ<4>")
	)
	(segment
		(start 40.111934 -227.835714)
		(end 39.38651 -227.835714)
		(width 0.18288)
		(layer "In6.Cu")
		(net "M_C_CPU1_SB_DQ<4>")
	)
	(segment
		(start 33.865566 -226.823778)
		(end 33.865566 -227.065078)
		(width 0.18288)
		(layer "In6.Cu")
		(net "M_C_CPU1_SB_DQ<4>")
	)
	(segment
		(start 34.048446 -226.640898)
		(end 33.865566 -226.823778)
		(width 0.18288)
		(layer "In6.Cu")
		(net "M_C_CPU1_SB_DQ<4>")
	)
	(segment
		(start 48.616108 -230.891334)
		(end 47.766478 -230.041704)
		(width 0.18288)
		(layer "In6.Cu")
		(net "M_C_CPU1_SB_DQ<4>")
	)
	(segment
		(start 44.97578 -229.192328)
		(end 42.50436 -229.192328)
		(width 0.18288)
		(layer "In6.Cu")
		(net "M_C_CPU1_SB_DQ<4>")
	)
	(segment
		(start 33.174686 -226.823778)
		(end 32.991806 -226.640898)
		(width 0.18288)
		(layer "In6.Cu")
		(net "M_C_CPU1_SB_DQ<4>")
	)
	(segment
		(start 32.300926 -226.640898)
		(end 31.876746 -226.216718)
		(width 0.18288)
		(layer "In6.Cu")
		(net "M_C_CPU1_SB_DQ<4>")
	)
	(segment
		(start 86.548468 -241.156744)
		(end 86.538054 -241.16284)
		(width 0.088646)
		(layer "In6.Cu")
		(net "M_C_CPU1_SB_DQ<4>")
	)
	(segment
		(start 35.247326 -227.065078)
		(end 35.064446 -227.247958)
		(width 0.18288)
		(layer "In6.Cu")
		(net "M_C_CPU1_SB_DQ<4>")
	)
	(segment
		(start 41.631362 -228.31933)
		(end 40.59555 -228.31933)
		(width 0.18288)
		(layer "In6.Cu")
		(net "M_C_CPU1_SB_DQ<4>")
	)
	(segment
		(start 35.430206 -226.640898)
		(end 35.247326 -226.823778)
		(width 0.18288)
		(layer "In6.Cu")
		(net "M_C_CPU1_SB_DQ<4>")
	)
	(segment
		(start 33.682686 -227.247958)
		(end 33.357566 -227.247958)
		(width 0.18288)
		(layer "In6.Cu")
		(net "M_C_CPU1_SB_DQ<4>")
	)
	(segment
		(start 89.367614 -241.156744)
		(end 89.352882 -241.16538)
		(width 0.088646)
		(layer "In6.Cu")
		(net "M_C_CPU1_SB_DQ<4>")
	)
	(segment
		(start 63.5381 -233.373168)
		(end 62.756542 -232.59161)
		(width 0.18288)
		(layer "In6.Cu")
		(net "M_C_CPU1_SB_DQ<4>")
	)
	(segment
		(start 94.066868 -241.156744)
		(end 94.056454 -241.16284)
		(width 0.088646)
		(layer "In6.Cu")
		(net "M_C_CPU1_SB_DQ<4>")
	)
	(segment
		(start 59.730894 -232.59161)
		(end 58.79211 -231.652826)
		(width 0.18288)
		(layer "In6.Cu")
		(net "M_C_CPU1_SB_DQ<4>")
	)
	(segment
		(start 72.026272 -239.80775)
		(end 72.026272 -239.804956)
		(width 0.18288)
		(layer "In6.Cu")
		(net "M_C_CPU1_SB_DQ<4>")
	)
	(segment
		(start 90.307414 -241.156744)
		(end 90.292682 -241.16538)
		(width 0.088646)
		(layer "In6.Cu")
		(net "M_C_CPU1_SB_DQ<4>")
	)
	(segment
		(start 35.064446 -227.247958)
		(end 34.739326 -227.247958)
		(width 0.18288)
		(layer "In6.Cu")
		(net "M_C_CPU1_SB_DQ<4>")
	)
	(segment
		(start 62.756542 -232.59161)
		(end 59.730894 -232.59161)
		(width 0.18288)
		(layer "In6.Cu")
		(net "M_C_CPU1_SB_DQ<4>")
	)
	(segment
		(start 72.026272 -239.804956)
		(end 67.226688 -235.005372)
		(width 0.18288)
		(layer "In6.Cu")
		(net "M_C_CPU1_SB_DQ<4>")
	)
	(segment
		(start 39.38651 -227.835714)
		(end 38.191694 -226.640898)
		(width 0.18288)
		(layer "In6.Cu")
		(net "M_C_CPU1_SB_DQ<4>")
	)
	(segment
		(start 40.59555 -228.31933)
		(end 40.111934 -227.835714)
		(width 0.18288)
		(layer "In6.Cu")
		(net "M_C_CPU1_SB_DQ<4>")
	)
	(segment
		(start 83.570064 -239.99063)
		(end 83.387184 -239.80775)
		(width 0.088646)
		(layer "In6.Cu")
		(net "M_C_CPU1_SB_DQ<4>")
	)
	(segment
		(start 94.679262 -241.231166)
		(end 94.656402 -241.228372)
		(width 0.088646)
		(layer "In6.Cu")
		(net "M_C_CPU1_SB_DQ<4>")
	)
	(segment
		(start 83.570064 -240.098834)
		(end 83.570064 -239.99063)
		(width 0.088646)
		(layer "In6.Cu")
		(net "M_C_CPU1_SB_DQ<4>")
	)
	(segment
		(start 83.387184 -239.80775)
		(end 83.089496 -239.80775)
		(width 0.088646)
		(layer "In6.Cu")
		(net "M_C_CPU1_SB_DQ<4>")
	)
	(segment
		(start 83.089496 -239.80775)
		(end 72.026272 -239.80775)
		(width 0.18288)
		(layer "In6.Cu")
		(net "M_C_CPU1_SB_DQ<4>")
	)
	(segment
		(start 64.165226 -233.373168)
		(end 63.5381 -233.373168)
		(width 0.18288)
		(layer "In6.Cu")
		(net "M_C_CPU1_SB_DQ<4>")
	)
	(segment
		(start 32.991806 -226.640898)
		(end 32.300926 -226.640898)
		(width 0.18288)
		(layer "In6.Cu")
		(net "M_C_CPU1_SB_DQ<4>")
	)
	(segment
		(start 55.024274 -230.891334)
		(end 48.616108 -230.891334)
		(width 0.18288)
		(layer "In6.Cu")
		(net "M_C_CPU1_SB_DQ<4>")
	)
	(segment
		(start 55.785766 -231.652826)
		(end 55.024274 -230.891334)
		(width 0.18288)
		(layer "In6.Cu")
		(net "M_C_CPU1_SB_DQ<4>")
	)
	(segment
		(start 35.247326 -226.823778)
		(end 35.247326 -227.065078)
		(width 0.18288)
		(layer "In6.Cu")
		(net "M_C_CPU1_SB_DQ<4>")
	)
	(segment
		(start 38.191694 -226.640898)
		(end 35.430206 -226.640898)
		(width 0.18288)
		(layer "In6.Cu")
		(net "M_C_CPU1_SB_DQ<4>")
	)
	(arc
		(start 94.056454 -241.16284)
		(mid 93.778022 -241.232686)
		(end 93.50121 -241.156744)
		(width 0.088646)
		(layer "In6.Cu")
		(net "M_C_CPU1_SB_DQ<4>")
	)
	(arc
		(start 85.98281 -241.156744)
		(mid 85.795612 -241.106601)
		(end 85.608414 -241.156744)
		(width 0.088646)
		(layer "In6.Cu")
		(net "M_C_CPU1_SB_DQ<4>")
	)
	(arc
		(start 86.922864 -241.156744)
		(mid 86.735666 -241.106601)
		(end 86.548468 -241.156744)
		(width 0.088646)
		(layer "In6.Cu")
		(net "M_C_CPU1_SB_DQ<4>")
	)
	(arc
		(start 85.04301 -241.156744)
		(mid 84.952857 -241.119203)
		(end 84.856066 -241.106198)
		(width 0.088646)
		(layer "In6.Cu")
		(net "M_C_CPU1_SB_DQ<4>")
	)
	(arc
		(start 90.292682 -241.16538)
		(mid 90.016207 -241.2327)
		(end 89.74201 -241.156744)
		(width 0.088646)
		(layer "In6.Cu")
		(net "M_C_CPU1_SB_DQ<4>")
	)
	(arc
		(start 92.172282 -241.16538)
		(mid 91.895807 -241.2327)
		(end 91.62161 -241.156744)
		(width 0.088646)
		(layer "In6.Cu")
		(net "M_C_CPU1_SB_DQ<4>")
	)
	(arc
		(start 85.593682 -241.16538)
		(mid 85.317207 -241.2327)
		(end 85.04301 -241.156744)
		(width 0.088646)
		(layer "In6.Cu")
		(net "M_C_CPU1_SB_DQ<4>")
	)
	(arc
		(start 92.56141 -241.156744)
		(mid 92.374212 -241.106601)
		(end 92.187014 -241.156744)
		(width 0.088646)
		(layer "In6.Cu")
		(net "M_C_CPU1_SB_DQ<4>")
	)
	(arc
		(start 88.80221 -241.156744)
		(mid 88.615012 -241.106601)
		(end 88.427814 -241.156744)
		(width 0.088646)
		(layer "In6.Cu")
		(net "M_C_CPU1_SB_DQ<4>")
	)
	(arc
		(start 94.441264 -241.156744)
		(mid 94.254066 -241.106601)
		(end 94.066868 -241.156744)
		(width 0.088646)
		(layer "In6.Cu")
		(net "M_C_CPU1_SB_DQ<4>")
	)
	(arc
		(start 95.193612 -241.481102)
		(mid 94.957444 -241.312897)
		(end 94.679262 -241.231166)
		(width 0.088646)
		(layer "In6.Cu")
		(net "M_C_CPU1_SB_DQ<4>")
	)
	(arc
		(start 89.352882 -241.16538)
		(mid 89.076407 -241.2327)
		(end 88.80221 -241.156744)
		(width 0.088646)
		(layer "In6.Cu")
		(net "M_C_CPU1_SB_DQ<4>")
	)
	(arc
		(start 91.62161 -241.156744)
		(mid 91.434412 -241.106601)
		(end 91.247214 -241.156744)
		(width 0.088646)
		(layer "In6.Cu")
		(net "M_C_CPU1_SB_DQ<4>")
	)
	(arc
		(start 87.488268 -241.156744)
		(mid 87.205566 -241.23252)
		(end 86.922864 -241.156744)
		(width 0.088646)
		(layer "In6.Cu")
		(net "M_C_CPU1_SB_DQ<4>")
	)
	(arc
		(start 94.656402 -241.228372)
		(mid 94.545203 -241.20346)
		(end 94.441264 -241.156744)
		(width 0.088646)
		(layer "In6.Cu")
		(net "M_C_CPU1_SB_DQ<4>")
	)
	(arc
		(start 90.68181 -241.156744)
		(mid 90.494612 -241.106601)
		(end 90.307414 -241.156744)
		(width 0.088646)
		(layer "In6.Cu")
		(net "M_C_CPU1_SB_DQ<4>")
	)
	(arc
		(start 93.50121 -241.156744)
		(mid 93.314012 -241.106601)
		(end 93.126814 -241.156744)
		(width 0.088646)
		(layer "In6.Cu")
		(net "M_C_CPU1_SB_DQ<4>")
	)
	(arc
		(start 93.112082 -241.16538)
		(mid 92.835607 -241.2327)
		(end 92.56141 -241.156744)
		(width 0.088646)
		(layer "In6.Cu")
		(net "M_C_CPU1_SB_DQ<4>")
	)
	(arc
		(start 87.862664 -241.156744)
		(mid 87.675466 -241.106601)
		(end 87.488268 -241.156744)
		(width 0.088646)
		(layer "In6.Cu")
		(net "M_C_CPU1_SB_DQ<4>")
	)
	(arc
		(start 86.538054 -241.16284)
		(mid 86.259622 -241.232686)
		(end 85.98281 -241.156744)
		(width 0.088646)
		(layer "In6.Cu")
		(net "M_C_CPU1_SB_DQ<4>")
	)
	(arc
		(start 89.74201 -241.156744)
		(mid 89.554812 -241.106601)
		(end 89.367614 -241.156744)
		(width 0.088646)
		(layer "In6.Cu")
		(net "M_C_CPU1_SB_DQ<4>")
	)
	(arc
		(start 91.247214 -241.156744)
		(mid 90.964512 -241.23252)
		(end 90.68181 -241.156744)
		(width 0.088646)
		(layer "In6.Cu")
		(net "M_C_CPU1_SB_DQ<4>")
	)
	(arc
		(start 88.4174 -241.16284)
		(mid 88.139222 -241.232563)
		(end 87.862664 -241.156744)
		(width 0.088646)
		(layer "In6.Cu")
		(net "M_C_CPU1_SB_DQ<4>")
	)
	(segment
		(start 29.151326 -229.913434)
		(end 29.29382 -230.055928)
		(width 0.20066)
		(layer "F.Cu")
		(net "M_C_CPU1_SB_DQ<3>")
	)
	(segment
		(start 97.073212 -243.644674)
		(end 97.073212 -243.108988)
		(width 0.20066)
		(layer "F.Cu")
		(net "M_C_CPU1_SB_DQ<3>")
	)
	(segment
		(start 34.055812 -229.616762)
		(end 34.871914 -229.616762)
		(width 0.20066)
		(layer "F.Cu")
		(net "M_C_CPU1_SB_DQ<3>")
	)
	(segment
		(start 31.972758 -230.041704)
		(end 32.51708 -230.041704)
		(width 0.20066)
		(layer "F.Cu")
		(net "M_C_CPU1_SB_DQ<3>")
	)
	(segment
		(start 33.189926 -229.612444)
		(end 33.401762 -229.82428)
		(width 0.20066)
		(layer "F.Cu")
		(net "M_C_CPU1_SB_DQ<3>")
	)
	(segment
		(start 32.794702 -229.612444)
		(end 33.189926 -229.612444)
		(width 0.20066)
		(layer "F.Cu")
		(net "M_C_CPU1_SB_DQ<3>")
	)
	(segment
		(start 27.328114 -229.616762)
		(end 29.025342 -229.616762)
		(width 0.20066)
		(layer "F.Cu")
		(net "M_C_CPU1_SB_DQ<3>")
	)
	(segment
		(start 32.51708 -230.041704)
		(end 32.666178 -229.892606)
		(width 0.20066)
		(layer "F.Cu")
		(net "M_C_CPU1_SB_DQ<3>")
	)
	(segment
		(start 32.666178 -229.740968)
		(end 32.794702 -229.612444)
		(width 0.20066)
		(layer "F.Cu")
		(net "M_C_CPU1_SB_DQ<3>")
	)
	(segment
		(start 29.025342 -229.616762)
		(end 29.151326 -229.742746)
		(width 0.20066)
		(layer "F.Cu")
		(net "M_C_CPU1_SB_DQ<3>")
	)
	(segment
		(start 32.666178 -229.892606)
		(end 32.666178 -229.740968)
		(width 0.20066)
		(layer "F.Cu")
		(net "M_C_CPU1_SB_DQ<3>")
	)
	(segment
		(start 29.899864 -230.041704)
		(end 31.972758 -230.041704)
		(width 0.1016)
		(layer "F.Cu")
		(net "M_C_CPU1_SB_DQ<3>")
	)
	(segment
		(start 29.29382 -230.055928)
		(end 29.647642 -230.055928)
		(width 0.20066)
		(layer "F.Cu")
		(net "M_C_CPU1_SB_DQ<3>")
	)
	(segment
		(start 29.151326 -229.742746)
		(end 29.151326 -229.913434)
		(width 0.20066)
		(layer "F.Cu")
		(net "M_C_CPU1_SB_DQ<3>")
	)
	(segment
		(start 35.976814 -229.616762)
		(end 34.871914 -229.616762)
		(width 0.20066)
		(layer "F.Cu")
		(net "M_C_CPU1_SB_DQ<3>")
	)
	(segment
		(start 29.647642 -230.055928)
		(end 29.661866 -230.041704)
		(width 0.101854)
		(layer "F.Cu")
		(net "M_C_CPU1_SB_DQ<3>")
	)
	(segment
		(start 33.401762 -229.82428)
		(end 33.848294 -229.82428)
		(width 0.20066)
		(layer "F.Cu")
		(net "M_C_CPU1_SB_DQ<3>")
	)
	(segment
		(start 97.073466 -243.644928)
		(end 97.073212 -243.644674)
		(width 0.20066)
		(layer "F.Cu")
		(net "M_C_CPU1_SB_DQ<3>")
	)
	(segment
		(start 29.661866 -230.041704)
		(end 29.899864 -230.041704)
		(width 0.101854)
		(layer "F.Cu")
		(net "M_C_CPU1_SB_DQ<3>")
	)
	(segment
		(start 33.848294 -229.82428)
		(end 34.055812 -229.616762)
		(width 0.20066)
		(layer "F.Cu")
		(net "M_C_CPU1_SB_DQ<3>")
	)
	(segment
		(start 43.269662 -232.994962)
		(end 41.992296 -231.717596)
		(width 0.18288)
		(layer "In6.Cu")
		(net "M_C_CPU1_SB_DQ<3>")
	)
	(segment
		(start 84.118196 -243.42471)
		(end 84.033614 -243.42471)
		(width 0.088646)
		(layer "In6.Cu")
		(net "M_C_CPU1_SB_DQ<3>")
	)
	(segment
		(start 61.286644 -236.521498)
		(end 61.103764 -236.338618)
		(width 0.18288)
		(layer "In6.Cu")
		(net "M_C_CPU1_SB_DQ<3>")
	)
	(segment
		(start 94.446344 -243.430552)
		(end 94.435422 -243.436648)
		(width 0.088646)
		(layer "In6.Cu")
		(net "M_C_CPU1_SB_DQ<3>")
	)
	(segment
		(start 60.778644 -236.338618)
		(end 60.595764 -236.521498)
		(width 0.18288)
		(layer "In6.Cu")
		(net "M_C_CPU1_SB_DQ<3>")
	)
	(segment
		(start 95.381064 -242.784376)
		(end 95.375222 -242.781074)
		(width 0.088646)
		(layer "In6.Cu")
		(net "M_C_CPU1_SB_DQ<3>")
	)
	(segment
		(start 52.686966 -234.95889)
		(end 52.504086 -235.14177)
		(width 0.18288)
		(layer "In6.Cu")
		(net "M_C_CPU1_SB_DQ<3>")
	)
	(segment
		(start 44.01693 -233.74223)
		(end 44.01693 -233.483658)
		(width 0.18288)
		(layer "In6.Cu")
		(net "M_C_CPU1_SB_DQ<3>")
	)
	(segment
		(start 55.915306 -236.033564)
		(end 55.023512 -235.14177)
		(width 0.18288)
		(layer "In6.Cu")
		(net "M_C_CPU1_SB_DQ<3>")
	)
	(segment
		(start 61.103764 -236.338618)
		(end 60.778644 -236.338618)
		(width 0.18288)
		(layer "In6.Cu")
		(net "M_C_CPU1_SB_DQ<3>")
	)
	(segment
		(start 53.377846 -234.702604)
		(end 53.194966 -234.519724)
		(width 0.18288)
		(layer "In6.Cu")
		(net "M_C_CPU1_SB_DQ<3>")
	)
	(segment
		(start 91.627706 -243.430044)
		(end 91.616022 -243.436648)
		(width 0.088646)
		(layer "In6.Cu")
		(net "M_C_CPU1_SB_DQ<3>")
	)
	(segment
		(start 60.412884 -236.859826)
		(end 59.629294 -236.859826)
		(width 0.18288)
		(layer "In6.Cu")
		(net "M_C_CPU1_SB_DQ<3>")
	)
	(segment
		(start 44.191174 -233.309414)
		(end 44.191174 -233.050842)
		(width 0.18288)
		(layer "In6.Cu")
		(net "M_C_CPU1_SB_DQ<3>")
	)
	(segment
		(start 90.687906 -243.430044)
		(end 90.676222 -243.436648)
		(width 0.088646)
		(layer "In6.Cu")
		(net "M_C_CPU1_SB_DQ<3>")
	)
	(segment
		(start 53.560726 -235.14177)
		(end 53.377846 -234.95889)
		(width 0.18288)
		(layer "In6.Cu")
		(net "M_C_CPU1_SB_DQ<3>")
	)
	(segment
		(start 58.803032 -236.033564)
		(end 57.673494 -236.033564)
		(width 0.18288)
		(layer "In6.Cu")
		(net "M_C_CPU1_SB_DQ<3>")
	)
	(segment
		(start 85.057996 -243.42471)
		(end 85.043264 -243.433346)
		(width 0.088646)
		(layer "In6.Cu")
		(net "M_C_CPU1_SB_DQ<3>")
	)
	(segment
		(start 37.507926 -230.07828)
		(end 36.438332 -230.07828)
		(width 0.18288)
		(layer "In6.Cu")
		(net "M_C_CPU1_SB_DQ<3>")
	)
	(segment
		(start 84.033614 -243.42471)
		(end 83.383374 -242.77447)
		(width 0.088646)
		(layer "In6.Cu")
		(net "M_C_CPU1_SB_DQ<3>")
	)
	(segment
		(start 82.074004 -241.934492)
		(end 71.080376 -241.934492)
		(width 0.18288)
		(layer "In6.Cu")
		(net "M_C_CPU1_SB_DQ<3>")
	)
	(segment
		(start 61.286644 -236.676946)
		(end 61.286644 -236.521498)
		(width 0.18288)
		(layer "In6.Cu")
		(net "M_C_CPU1_SB_DQ<3>")
	)
	(segment
		(start 44.566332 -234.291632)
		(end 44.01693 -233.74223)
		(width 0.18288)
		(layer "In6.Cu")
		(net "M_C_CPU1_SB_DQ<3>")
	)
	(segment
		(start 85.997796 -243.42471)
		(end 85.983064 -243.433346)
		(width 0.088646)
		(layer "In6.Cu")
		(net "M_C_CPU1_SB_DQ<3>")
	)
	(segment
		(start 45.440092 -234.108752)
		(end 45.257212 -234.291632)
		(width 0.18288)
		(layer "In6.Cu")
		(net "M_C_CPU1_SB_DQ<3>")
	)
	(segment
		(start 60.595764 -236.521498)
		(end 60.595764 -236.676946)
		(width 0.18288)
		(layer "In6.Cu")
		(net "M_C_CPU1_SB_DQ<3>")
	)
	(segment
		(start 61.469524 -236.859826)
		(end 61.286644 -236.676946)
		(width 0.18288)
		(layer "In6.Cu")
		(net "M_C_CPU1_SB_DQ<3>")
	)
	(segment
		(start 88.802464 -243.433346)
		(end 88.798654 -243.435632)
		(width 0.088646)
		(layer "In6.Cu")
		(net "M_C_CPU1_SB_DQ<3>")
	)
	(segment
		(start 89.748106 -243.430044)
		(end 89.736422 -243.436648)
		(width 0.088646)
		(layer "In6.Cu")
		(net "M_C_CPU1_SB_DQ<3>")
	)
	(segment
		(start 88.427814 -243.433346)
		(end 88.4174 -243.42725)
		(width 0.088646)
		(layer "In6.Cu")
		(net "M_C_CPU1_SB_DQ<3>")
	)
	(segment
		(start 66.810636 -237.664752)
		(end 65.160652 -237.664752)
		(width 0.18288)
		(layer "In6.Cu")
		(net "M_C_CPU1_SB_DQ<3>")
	)
	(segment
		(start 83.089496 -242.77447)
		(end 82.913982 -242.77447)
		(width 0.18288)
		(layer "In6.Cu")
		(net "M_C_CPU1_SB_DQ<3>")
	)
	(segment
		(start 45.622972 -233.735118)
		(end 45.440092 -233.917998)
		(width 0.18288)
		(layer "In6.Cu")
		(net "M_C_CPU1_SB_DQ<3>")
	)
	(segment
		(start 64.355726 -236.859826)
		(end 61.469524 -236.859826)
		(width 0.18288)
		(layer "In6.Cu")
		(net "M_C_CPU1_SB_DQ<3>")
	)
	(segment
		(start 38.290246 -230.8606)
		(end 37.507926 -230.07828)
		(width 0.18288)
		(layer "In6.Cu")
		(net "M_C_CPU1_SB_DQ<3>")
	)
	(segment
		(start 45.440092 -233.917998)
		(end 45.440092 -234.108752)
		(width 0.18288)
		(layer "In6.Cu")
		(net "M_C_CPU1_SB_DQ<3>")
	)
	(segment
		(start 60.595764 -236.676946)
		(end 60.412884 -236.859826)
		(width 0.18288)
		(layer "In6.Cu")
		(net "M_C_CPU1_SB_DQ<3>")
	)
	(segment
		(start 86.937596 -243.42471)
		(end 86.922864 -243.433346)
		(width 0.088646)
		(layer "In6.Cu")
		(net "M_C_CPU1_SB_DQ<3>")
	)
	(segment
		(start 50.01387 -235.14177)
		(end 49.163732 -234.291632)
		(width 0.18288)
		(layer "In6.Cu")
		(net "M_C_CPU1_SB_DQ<3>")
	)
	(segment
		(start 56.799734 -235.472478)
		(end 56.799734 -235.850684)
		(width 0.18288)
		(layer "In6.Cu")
		(net "M_C_CPU1_SB_DQ<3>")
	)
	(segment
		(start 57.307734 -235.289598)
		(end 56.982614 -235.289598)
		(width 0.18288)
		(layer "In6.Cu")
		(net "M_C_CPU1_SB_DQ<3>")
	)
	(segment
		(start 94.639892 -243.183664)
		(end 94.582996 -243.288058)
		(width 0.088646)
		(layer "In6.Cu")
		(net "M_C_CPU1_SB_DQ<3>")
	)
	(segment
		(start 65.160652 -237.664752)
		(end 64.355726 -236.859826)
		(width 0.18288)
		(layer "In6.Cu")
		(net "M_C_CPU1_SB_DQ<3>")
	)
	(segment
		(start 56.982614 -235.289598)
		(end 56.799734 -235.472478)
		(width 0.18288)
		(layer "In6.Cu")
		(net "M_C_CPU1_SB_DQ<3>")
	)
	(segment
		(start 53.194966 -234.519724)
		(end 52.869846 -234.519724)
		(width 0.18288)
		(layer "In6.Cu")
		(net "M_C_CPU1_SB_DQ<3>")
	)
	(segment
		(start 40.577262 -231.717596)
		(end 39.720266 -230.8606)
		(width 0.18288)
		(layer "In6.Cu")
		(net "M_C_CPU1_SB_DQ<3>")
	)
	(segment
		(start 56.799734 -235.850684)
		(end 56.616854 -236.033564)
		(width 0.18288)
		(layer "In6.Cu")
		(net "M_C_CPU1_SB_DQ<3>")
	)
	(segment
		(start 53.377846 -234.95889)
		(end 53.377846 -234.702604)
		(width 0.18288)
		(layer "In6.Cu")
		(net "M_C_CPU1_SB_DQ<3>")
	)
	(segment
		(start 96.718628 -243.013992)
		(end 96.315022 -242.781074)
		(width 0.088646)
		(layer "In6.Cu")
		(net "M_C_CPU1_SB_DQ<3>")
	)
	(segment
		(start 83.383374 -242.77447)
		(end 83.089496 -242.77447)
		(width 0.088646)
		(layer "In6.Cu")
		(net "M_C_CPU1_SB_DQ<3>")
	)
	(segment
		(start 45.257212 -234.291632)
		(end 44.566332 -234.291632)
		(width 0.18288)
		(layer "In6.Cu")
		(net "M_C_CPU1_SB_DQ<3>")
	)
	(segment
		(start 46.130972 -233.917998)
		(end 45.948092 -233.735118)
		(width 0.18288)
		(layer "In6.Cu")
		(net "M_C_CPU1_SB_DQ<3>")
	)
	(segment
		(start 44.191174 -233.050842)
		(end 43.96105 -232.820718)
		(width 0.18288)
		(layer "In6.Cu")
		(net "M_C_CPU1_SB_DQ<3>")
	)
	(segment
		(start 45.948092 -233.735118)
		(end 45.622972 -233.735118)
		(width 0.18288)
		(layer "In6.Cu")
		(net "M_C_CPU1_SB_DQ<3>")
	)
	(segment
		(start 41.992296 -231.717596)
		(end 40.577262 -231.717596)
		(width 0.18288)
		(layer "In6.Cu")
		(net "M_C_CPU1_SB_DQ<3>")
	)
	(segment
		(start 57.490614 -235.472478)
		(end 57.307734 -235.289598)
		(width 0.18288)
		(layer "In6.Cu")
		(net "M_C_CPU1_SB_DQ<3>")
	)
	(segment
		(start 43.96105 -232.820718)
		(end 43.702478 -232.820718)
		(width 0.18288)
		(layer "In6.Cu")
		(net "M_C_CPU1_SB_DQ<3>")
	)
	(segment
		(start 43.702478 -232.820718)
		(end 43.528234 -232.994962)
		(width 0.18288)
		(layer "In6.Cu")
		(net "M_C_CPU1_SB_DQ<3>")
	)
	(segment
		(start 39.720266 -230.8606)
		(end 38.290246 -230.8606)
		(width 0.18288)
		(layer "In6.Cu")
		(net "M_C_CPU1_SB_DQ<3>")
	)
	(segment
		(start 46.130972 -234.108752)
		(end 46.130972 -233.917998)
		(width 0.18288)
		(layer "In6.Cu")
		(net "M_C_CPU1_SB_DQ<3>")
	)
	(segment
		(start 56.616854 -236.033564)
		(end 55.915306 -236.033564)
		(width 0.18288)
		(layer "In6.Cu")
		(net "M_C_CPU1_SB_DQ<3>")
	)
	(segment
		(start 59.629294 -236.859826)
		(end 58.803032 -236.033564)
		(width 0.18288)
		(layer "In6.Cu")
		(net "M_C_CPU1_SB_DQ<3>")
	)
	(segment
		(start 43.528234 -232.994962)
		(end 43.269662 -232.994962)
		(width 0.18288)
		(layer "In6.Cu")
		(net "M_C_CPU1_SB_DQ<3>")
	)
	(segment
		(start 52.869846 -234.519724)
		(end 52.686966 -234.702604)
		(width 0.18288)
		(layer "In6.Cu")
		(net "M_C_CPU1_SB_DQ<3>")
	)
	(segment
		(start 71.080376 -241.934492)
		(end 66.810636 -237.664752)
		(width 0.18288)
		(layer "In6.Cu")
		(net "M_C_CPU1_SB_DQ<3>")
	)
	(segment
		(start 94.905576 -242.861846)
		(end 94.8055 -242.961922)
		(width 0.088646)
		(layer "In6.Cu")
		(net "M_C_CPU1_SB_DQ<3>")
	)
	(segment
		(start 49.163732 -234.291632)
		(end 46.313852 -234.291632)
		(width 0.18288)
		(layer "In6.Cu")
		(net "M_C_CPU1_SB_DQ<3>")
	)
	(segment
		(start 57.490614 -235.850684)
		(end 57.490614 -235.472478)
		(width 0.18288)
		(layer "In6.Cu")
		(net "M_C_CPU1_SB_DQ<3>")
	)
	(segment
		(start 57.673494 -236.033564)
		(end 57.490614 -235.850684)
		(width 0.18288)
		(layer "In6.Cu")
		(net "M_C_CPU1_SB_DQ<3>")
	)
	(segment
		(start 55.023512 -235.14177)
		(end 53.560726 -235.14177)
		(width 0.18288)
		(layer "In6.Cu")
		(net "M_C_CPU1_SB_DQ<3>")
	)
	(segment
		(start 92.567506 -243.430044)
		(end 92.555822 -243.436648)
		(width 0.088646)
		(layer "In6.Cu")
		(net "M_C_CPU1_SB_DQ<3>")
	)
	(segment
		(start 82.913982 -242.77447)
		(end 82.074004 -241.934492)
		(width 0.18288)
		(layer "In6.Cu")
		(net "M_C_CPU1_SB_DQ<3>")
	)
	(segment
		(start 36.438332 -230.07828)
		(end 35.976814 -229.616762)
		(width 0.18288)
		(layer "In6.Cu")
		(net "M_C_CPU1_SB_DQ<3>")
	)
	(segment
		(start 46.313852 -234.291632)
		(end 46.130972 -234.108752)
		(width 0.18288)
		(layer "In6.Cu")
		(net "M_C_CPU1_SB_DQ<3>")
	)
	(segment
		(start 44.01693 -233.483658)
		(end 44.191174 -233.309414)
		(width 0.18288)
		(layer "In6.Cu")
		(net "M_C_CPU1_SB_DQ<3>")
	)
	(segment
		(start 88.808306 -243.430044)
		(end 88.802464 -243.433346)
		(width 0.088646)
		(layer "In6.Cu")
		(net "M_C_CPU1_SB_DQ<3>")
	)
	(segment
		(start 52.504086 -235.14177)
		(end 50.01387 -235.14177)
		(width 0.18288)
		(layer "In6.Cu")
		(net "M_C_CPU1_SB_DQ<3>")
	)
	(segment
		(start 52.686966 -234.702604)
		(end 52.686966 -234.95889)
		(width 0.18288)
		(layer "In6.Cu")
		(net "M_C_CPU1_SB_DQ<3>")
	)
	(segment
		(start 93.507306 -243.430044)
		(end 93.495622 -243.436648)
		(width 0.088646)
		(layer "In6.Cu")
		(net "M_C_CPU1_SB_DQ<3>")
	)
	(segment
		(start 95.386906 -242.787932)
		(end 95.381064 -242.784376)
		(width 0.088646)
		(layer "In6.Cu")
		(net "M_C_CPU1_SB_DQ<3>")
	)
	(arc
		(start 95.946214 -242.784376)
		(mid 95.66704 -242.860141)
		(end 95.386906 -242.787932)
		(width 0.088646)
		(layer "In6.Cu")
		(net "M_C_CPU1_SB_DQ<3>")
	)
	(arc
		(start 91.247214 -243.433346)
		(mid 90.968011 -243.357706)
		(end 90.687906 -243.430044)
		(width 0.088646)
		(layer "In6.Cu")
		(net "M_C_CPU1_SB_DQ<3>")
	)
	(arc
		(start 93.495622 -243.436648)
		(mid 93.310767 -243.483598)
		(end 93.126814 -243.433346)
		(width 0.088646)
		(layer "In6.Cu")
		(net "M_C_CPU1_SB_DQ<3>")
	)
	(arc
		(start 92.555822 -243.436648)
		(mid 92.370967 -243.483598)
		(end 92.187014 -243.433346)
		(width 0.088646)
		(layer "In6.Cu")
		(net "M_C_CPU1_SB_DQ<3>")
	)
	(arc
		(start 85.043264 -243.433346)
		(mid 84.856066 -243.483489)
		(end 84.668868 -243.433346)
		(width 0.088646)
		(layer "In6.Cu")
		(net "M_C_CPU1_SB_DQ<3>")
	)
	(arc
		(start 86.548468 -243.433346)
		(mid 86.274269 -243.357511)
		(end 85.997796 -243.42471)
		(width 0.088646)
		(layer "In6.Cu")
		(net "M_C_CPU1_SB_DQ<3>")
	)
	(arc
		(start 94.8055 -242.961922)
		(mid 94.714728 -243.066841)
		(end 94.639892 -243.183664)
		(width 0.088646)
		(layer "In6.Cu")
		(net "M_C_CPU1_SB_DQ<3>")
	)
	(arc
		(start 94.435422 -243.436648)
		(mid 94.250567 -243.483598)
		(end 94.066614 -243.433346)
		(width 0.088646)
		(layer "In6.Cu")
		(net "M_C_CPU1_SB_DQ<3>")
	)
	(arc
		(start 97.073212 -243.108988)
		(mid 96.889669 -243.084825)
		(end 96.718628 -243.013992)
		(width 0.088646)
		(layer "In6.Cu")
		(net "M_C_CPU1_SB_DQ<3>")
	)
	(arc
		(start 91.616022 -243.436648)
		(mid 91.431167 -243.483598)
		(end 91.247214 -243.433346)
		(width 0.088646)
		(layer "In6.Cu")
		(net "M_C_CPU1_SB_DQ<3>")
	)
	(arc
		(start 88.798654 -243.435632)
		(mid 88.612935 -243.483584)
		(end 88.427814 -243.433346)
		(width 0.088646)
		(layer "In6.Cu")
		(net "M_C_CPU1_SB_DQ<3>")
	)
	(arc
		(start 95.006414 -242.784376)
		(mid 94.95345 -242.819799)
		(end 94.905576 -242.861846)
		(width 0.088646)
		(layer "In6.Cu")
		(net "M_C_CPU1_SB_DQ<3>")
	)
	(arc
		(start 87.862664 -243.433346)
		(mid 87.675466 -243.483489)
		(end 87.488268 -243.433346)
		(width 0.088646)
		(layer "In6.Cu")
		(net "M_C_CPU1_SB_DQ<3>")
	)
	(arc
		(start 95.375222 -242.781074)
		(mid 95.190367 -242.734156)
		(end 95.006414 -242.784376)
		(width 0.088646)
		(layer "In6.Cu")
		(net "M_C_CPU1_SB_DQ<3>")
	)
	(arc
		(start 84.668868 -243.433346)
		(mid 84.394669 -243.357511)
		(end 84.118196 -243.42471)
		(width 0.088646)
		(layer "In6.Cu")
		(net "M_C_CPU1_SB_DQ<3>")
	)
	(arc
		(start 89.367614 -243.433346)
		(mid 89.088411 -243.357706)
		(end 88.808306 -243.430044)
		(width 0.088646)
		(layer "In6.Cu")
		(net "M_C_CPU1_SB_DQ<3>")
	)
	(arc
		(start 93.126814 -243.433346)
		(mid 92.847611 -243.357706)
		(end 92.567506 -243.430044)
		(width 0.088646)
		(layer "In6.Cu")
		(net "M_C_CPU1_SB_DQ<3>")
	)
	(arc
		(start 87.488268 -243.433346)
		(mid 87.214069 -243.357511)
		(end 86.937596 -243.42471)
		(width 0.088646)
		(layer "In6.Cu")
		(net "M_C_CPU1_SB_DQ<3>")
	)
	(arc
		(start 89.736422 -243.436648)
		(mid 89.551567 -243.483598)
		(end 89.367614 -243.433346)
		(width 0.088646)
		(layer "In6.Cu")
		(net "M_C_CPU1_SB_DQ<3>")
	)
	(arc
		(start 86.922864 -243.433346)
		(mid 86.735666 -243.483489)
		(end 86.548468 -243.433346)
		(width 0.088646)
		(layer "In6.Cu")
		(net "M_C_CPU1_SB_DQ<3>")
	)
	(arc
		(start 92.187014 -243.433346)
		(mid 91.907811 -243.357706)
		(end 91.627706 -243.430044)
		(width 0.088646)
		(layer "In6.Cu")
		(net "M_C_CPU1_SB_DQ<3>")
	)
	(arc
		(start 85.608668 -243.433346)
		(mid 85.334469 -243.357511)
		(end 85.057996 -243.42471)
		(width 0.088646)
		(layer "In6.Cu")
		(net "M_C_CPU1_SB_DQ<3>")
	)
	(arc
		(start 96.315022 -242.781074)
		(mid 96.130167 -242.734156)
		(end 95.946214 -242.784376)
		(width 0.088646)
		(layer "In6.Cu")
		(net "M_C_CPU1_SB_DQ<3>")
	)
	(arc
		(start 85.983064 -243.433346)
		(mid 85.795866 -243.483489)
		(end 85.608668 -243.433346)
		(width 0.088646)
		(layer "In6.Cu")
		(net "M_C_CPU1_SB_DQ<3>")
	)
	(arc
		(start 94.582996 -243.288058)
		(mid 94.524238 -243.368485)
		(end 94.446344 -243.430552)
		(width 0.088646)
		(layer "In6.Cu")
		(net "M_C_CPU1_SB_DQ<3>")
	)
	(arc
		(start 94.066614 -243.433346)
		(mid 93.787411 -243.357706)
		(end 93.507306 -243.430044)
		(width 0.088646)
		(layer "In6.Cu")
		(net "M_C_CPU1_SB_DQ<3>")
	)
	(arc
		(start 90.307414 -243.433346)
		(mid 90.028211 -243.357706)
		(end 89.748106 -243.430044)
		(width 0.088646)
		(layer "In6.Cu")
		(net "M_C_CPU1_SB_DQ<3>")
	)
	(arc
		(start 90.676222 -243.436648)
		(mid 90.491367 -243.483598)
		(end 90.307414 -243.433346)
		(width 0.088646)
		(layer "In6.Cu")
		(net "M_C_CPU1_SB_DQ<3>")
	)
	(arc
		(start 88.4174 -243.42725)
		(mid 88.139222 -243.357527)
		(end 87.862664 -243.433346)
		(width 0.088646)
		(layer "In6.Cu")
		(net "M_C_CPU1_SB_DQ<3>")
	)
	(segment
		(start 33.401762 -195.824094)
		(end 33.848294 -195.824094)
		(width 0.20066)
		(layer "F.Cu")
		(net "M_C_CPU1_SB_DQ<31>")
	)
	(segment
		(start 29.899864 -196.041518)
		(end 31.972758 -196.041518)
		(width 0.1016)
		(layer "F.Cu")
		(net "M_C_CPU1_SB_DQ<31>")
	)
	(segment
		(start 29.151326 -195.74256)
		(end 29.151326 -195.913248)
		(width 0.20066)
		(layer "F.Cu")
		(net "M_C_CPU1_SB_DQ<31>")
	)
	(segment
		(start 33.848294 -195.824094)
		(end 34.055812 -195.616576)
		(width 0.20066)
		(layer "F.Cu")
		(net "M_C_CPU1_SB_DQ<31>")
	)
	(segment
		(start 32.51708 -196.041518)
		(end 32.666178 -195.89242)
		(width 0.20066)
		(layer "F.Cu")
		(net "M_C_CPU1_SB_DQ<31>")
	)
	(segment
		(start 29.025342 -195.616576)
		(end 29.151326 -195.74256)
		(width 0.20066)
		(layer "F.Cu")
		(net "M_C_CPU1_SB_DQ<31>")
	)
	(segment
		(start 32.666178 -195.740782)
		(end 32.794702 -195.612258)
		(width 0.20066)
		(layer "F.Cu")
		(net "M_C_CPU1_SB_DQ<31>")
	)
	(segment
		(start 32.666178 -195.89242)
		(end 32.666178 -195.740782)
		(width 0.20066)
		(layer "F.Cu")
		(net "M_C_CPU1_SB_DQ<31>")
	)
	(segment
		(start 31.972758 -196.041518)
		(end 32.51708 -196.041518)
		(width 0.20066)
		(layer "F.Cu")
		(net "M_C_CPU1_SB_DQ<31>")
	)
	(segment
		(start 33.189926 -195.612258)
		(end 33.401762 -195.824094)
		(width 0.20066)
		(layer "F.Cu")
		(net "M_C_CPU1_SB_DQ<31>")
	)
	(segment
		(start 32.794702 -195.612258)
		(end 33.189926 -195.612258)
		(width 0.20066)
		(layer "F.Cu")
		(net "M_C_CPU1_SB_DQ<31>")
	)
	(segment
		(start 29.647642 -196.055742)
		(end 29.661866 -196.041518)
		(width 0.101854)
		(layer "F.Cu")
		(net "M_C_CPU1_SB_DQ<31>")
	)
	(segment
		(start 29.151326 -195.913248)
		(end 29.29382 -196.055742)
		(width 0.20066)
		(layer "F.Cu")
		(net "M_C_CPU1_SB_DQ<31>")
	)
	(segment
		(start 29.661866 -196.041518)
		(end 29.899864 -196.041518)
		(width 0.101854)
		(layer "F.Cu")
		(net "M_C_CPU1_SB_DQ<31>")
	)
	(segment
		(start 29.29382 -196.055742)
		(end 29.647642 -196.055742)
		(width 0.20066)
		(layer "F.Cu")
		(net "M_C_CPU1_SB_DQ<31>")
	)
	(segment
		(start 34.055812 -195.616576)
		(end 34.871914 -195.616576)
		(width 0.20066)
		(layer "F.Cu")
		(net "M_C_CPU1_SB_DQ<31>")
	)
	(segment
		(start 35.976814 -195.616576)
		(end 34.871914 -195.616576)
		(width 0.20066)
		(layer "F.Cu")
		(net "M_C_CPU1_SB_DQ<31>")
	)
	(segment
		(start 98.013012 -227.36683)
		(end 98.013012 -226.831144)
		(width 0.20066)
		(layer "F.Cu")
		(net "M_C_CPU1_SB_DQ<31>")
	)
	(segment
		(start 98.013266 -227.367084)
		(end 98.013012 -227.36683)
		(width 0.20066)
		(layer "F.Cu")
		(net "M_C_CPU1_SB_DQ<31>")
	)
	(segment
		(start 27.328114 -195.616576)
		(end 29.025342 -195.616576)
		(width 0.20066)
		(layer "F.Cu")
		(net "M_C_CPU1_SB_DQ<31>")
	)
	(segment
		(start 85.057996 -223.259904)
		(end 85.043264 -223.251268)
		(width 0.088646)
		(layer "In6.Cu")
		(net "M_C_CPU1_SB_DQ<31>")
	)
	(segment
		(start 56.425338 -194.14871)
		(end 56.420004 -194.208146)
		(width 0.18288)
		(layer "In6.Cu")
		(net "M_C_CPU1_SB_DQ<31>")
	)
	(segment
		(start 44.16044 -193.725292)
		(end 43.97756 -193.908172)
		(width 0.18288)
		(layer "In6.Cu")
		(net "M_C_CPU1_SB_DQ<31>")
	)
	(segment
		(start 92.657168 -224.065084)
		(end 92.648278 -224.070164)
		(width 0.088646)
		(layer "In6.Cu")
		(net "M_C_CPU1_SB_DQ<31>")
	)
	(segment
		(start 55.575454 -193.812668)
		(end 54.595014 -193.725292)
		(width 0.18288)
		(layer "In6.Cu")
		(net "M_C_CPU1_SB_DQ<31>")
	)
	(segment
		(start 97.657412 -226.926394)
		(end 97.26041 -227.155502)
		(width 0.088646)
		(layer "In6.Cu")
		(net "M_C_CPU1_SB_DQ<31>")
	)
	(segment
		(start 40.53459 -193.908172)
		(end 40.35171 -193.725292)
		(width 0.18288)
		(layer "In6.Cu")
		(net "M_C_CPU1_SB_DQ<31>")
	)
	(segment
		(start 61.790326 -196.829426)
		(end 60.647326 -195.686426)
		(width 0.18288)
		(layer "In6.Cu")
		(net "M_C_CPU1_SB_DQ<31>")
	)
	(segment
		(start 59.950604 -194.312032)
		(end 59.666124 -194.237864)
		(width 0.18288)
		(layer "In6.Cu")
		(net "M_C_CPU1_SB_DQ<31>")
	)
	(segment
		(start 43.1038 -193.725292)
		(end 41.41089 -193.725292)
		(width 0.18288)
		(layer "In6.Cu")
		(net "M_C_CPU1_SB_DQ<31>")
	)
	(segment
		(start 39.291006 -193.75755)
		(end 37.673788 -194.083686)
		(width 0.18288)
		(layer "In6.Cu")
		(net "M_C_CPU1_SB_DQ<31>")
	)
	(segment
		(start 56.432196 -194.072256)
		(end 56.425338 -194.14871)
		(width 0.18288)
		(layer "In6.Cu")
		(net "M_C_CPU1_SB_DQ<31>")
	)
	(segment
		(start 64.328294 -197.718426)
		(end 63.46698 -197.718426)
		(width 0.18288)
		(layer "In6.Cu")
		(net "M_C_CPU1_SB_DQ<31>")
	)
	(segment
		(start 96.731074 -227.038662)
		(end 96.564704 -226.750372)
		(width 0.088646)
		(layer "In6.Cu")
		(net "M_C_CPU1_SB_DQ<31>")
	)
	(segment
		(start 95.098616 -226.032822)
		(end 95.098616 -226.017328)
		(width 0.088646)
		(layer "In6.Cu")
		(net "M_C_CPU1_SB_DQ<31>")
	)
	(segment
		(start 55.730902 -194.14871)
		(end 55.729378 -194.146932)
		(width 0.18288)
		(layer "In6.Cu")
		(net "M_C_CPU1_SB_DQ<31>")
	)
	(segment
		(start 43.46956 -194.301364)
		(end 43.28668 -194.118484)
		(width 0.18288)
		(layer "In6.Cu")
		(net "M_C_CPU1_SB_DQ<31>")
	)
	(segment
		(start 88.428068 -223.251268)
		(end 88.413336 -223.259904)
		(width 0.088646)
		(layer "In6.Cu")
		(net "M_C_CPU1_SB_DQ<31>")
	)
	(segment
		(start 40.35171 -193.725292)
		(end 39.57066 -193.725292)
		(width 0.18288)
		(layer "In6.Cu")
		(net "M_C_CPU1_SB_DQ<31>")
	)
	(segment
		(start 59.666124 -194.237864)
		(end 58.87339 -194.105784)
		(width 0.18288)
		(layer "In6.Cu")
		(net "M_C_CPU1_SB_DQ<31>")
	)
	(segment
		(start 91.160854 -224.070164)
		(end 91.151964 -224.065084)
		(width 0.088646)
		(layer "In6.Cu")
		(net "M_C_CPU1_SB_DQ<31>")
	)
	(segment
		(start 96.886014 -227.155502)
		(end 96.79305 -227.101146)
		(width 0.088646)
		(layer "In6.Cu")
		(net "M_C_CPU1_SB_DQ<31>")
	)
	(segment
		(start 88.8111 -223.256348)
		(end 88.80221 -223.251268)
		(width 0.088646)
		(layer "In6.Cu")
		(net "M_C_CPU1_SB_DQ<31>")
	)
	(segment
		(start 37.673788 -194.083686)
		(end 36.958016 -194.331336)
		(width 0.18288)
		(layer "In6.Cu")
		(net "M_C_CPU1_SB_DQ<31>")
	)
	(segment
		(start 60.647326 -194.898772)
		(end 60.22848 -194.479926)
		(width 0.18288)
		(layer "In6.Cu")
		(net "M_C_CPU1_SB_DQ<31>")
	)
	(segment
		(start 89.281254 -224.070164)
		(end 89.272364 -224.065084)
		(width 0.088646)
		(layer "In6.Cu")
		(net "M_C_CPU1_SB_DQ<31>")
	)
	(segment
		(start 89.459816 -224.404936)
		(end 89.459816 -224.389442)
		(width 0.088646)
		(layer "In6.Cu")
		(net "M_C_CPU1_SB_DQ<31>")
	)
	(segment
		(start 93.5101 -224.88398)
		(end 93.50121 -224.8789)
		(width 0.088646)
		(layer "In6.Cu")
		(net "M_C_CPU1_SB_DQ<31>")
	)
	(segment
		(start 43.28668 -194.118484)
		(end 43.28668 -193.908172)
		(width 0.18288)
		(layer "In6.Cu")
		(net "M_C_CPU1_SB_DQ<31>")
	)
	(segment
		(start 55.729378 -194.146932)
		(end 55.74157 -194.010788)
		(width 0.18288)
		(layer "In6.Cu")
		(net "M_C_CPU1_SB_DQ<31>")
	)
	(segment
		(start 55.74157 -194.010788)
		(end 55.575454 -193.812668)
		(width 0.18288)
		(layer "In6.Cu")
		(net "M_C_CPU1_SB_DQ<31>")
	)
	(segment
		(start 84.760562 -222.77578)
		(end 84.760562 -221.76486)
		(width 0.088646)
		(layer "In6.Cu")
		(net "M_C_CPU1_SB_DQ<31>")
	)
	(segment
		(start 41.22801 -193.908172)
		(end 41.22801 -194.175126)
		(width 0.18288)
		(layer "In6.Cu")
		(net "M_C_CPU1_SB_DQ<31>")
	)
	(segment
		(start 62.57798 -196.829426)
		(end 61.790326 -196.829426)
		(width 0.18288)
		(layer "In6.Cu")
		(net "M_C_CPU1_SB_DQ<31>")
	)
	(segment
		(start 60.647326 -195.686426)
		(end 60.647326 -194.898772)
		(width 0.18288)
		(layer "In6.Cu")
		(net "M_C_CPU1_SB_DQ<31>")
	)
	(segment
		(start 83.06816 -220.072458)
		(end 82.570828 -219.575126)
		(width 0.18288)
		(layer "In6.Cu")
		(net "M_C_CPU1_SB_DQ<31>")
	)
	(segment
		(start 92.187014 -224.8789)
		(end 92.172282 -224.887536)
		(width 0.088646)
		(layer "In6.Cu")
		(net "M_C_CPU1_SB_DQ<31>")
	)
	(segment
		(start 43.97756 -193.908172)
		(end 43.97756 -194.118484)
		(width 0.18288)
		(layer "In6.Cu")
		(net "M_C_CPU1_SB_DQ<31>")
	)
	(segment
		(start 73.772268 -210.23199)
		(end 70.883272 -203.257912)
		(width 0.18288)
		(layer "In6.Cu")
		(net "M_C_CPU1_SB_DQ<31>")
	)
	(segment
		(start 56.63057 -193.90614)
		(end 56.432196 -194.072256)
		(width 0.18288)
		(layer "In6.Cu")
		(net "M_C_CPU1_SB_DQ<31>")
	)
	(segment
		(start 43.79468 -194.301364)
		(end 43.46956 -194.301364)
		(width 0.18288)
		(layer "In6.Cu")
		(net "M_C_CPU1_SB_DQ<31>")
	)
	(segment
		(start 55.894986 -194.344798)
		(end 55.730902 -194.14871)
		(width 0.18288)
		(layer "In6.Cu")
		(net "M_C_CPU1_SB_DQ<31>")
	)
	(segment
		(start 89.272364 -224.065084)
		(end 89.260172 -224.057972)
		(width 0.088646)
		(layer "In6.Cu")
		(net "M_C_CPU1_SB_DQ<31>")
	)
	(segment
		(start 56.222138 -194.374008)
		(end 55.894986 -194.344798)
		(width 0.18288)
		(layer "In6.Cu")
		(net "M_C_CPU1_SB_DQ<31>")
	)
	(segment
		(start 56.420004 -194.208146)
		(end 56.222138 -194.374008)
		(width 0.18288)
		(layer "In6.Cu")
		(net "M_C_CPU1_SB_DQ<31>")
	)
	(segment
		(start 66.872612 -199.247252)
		(end 65.85712 -199.247252)
		(width 0.18288)
		(layer "In6.Cu")
		(net "M_C_CPU1_SB_DQ<31>")
	)
	(segment
		(start 70.883272 -203.257912)
		(end 66.872612 -199.247252)
		(width 0.18288)
		(layer "In6.Cu")
		(net "M_C_CPU1_SB_DQ<31>")
	)
	(segment
		(start 60.22848 -194.479926)
		(end 59.950604 -194.312032)
		(width 0.18288)
		(layer "In6.Cu")
		(net "M_C_CPU1_SB_DQ<31>")
	)
	(segment
		(start 54.595014 -193.725292)
		(end 44.16044 -193.725292)
		(width 0.18288)
		(layer "In6.Cu")
		(net "M_C_CPU1_SB_DQ<31>")
	)
	(segment
		(start 93.986096 -225.701606)
		(end 93.971364 -225.69297)
		(width 0.088646)
		(layer "In6.Cu")
		(net "M_C_CPU1_SB_DQ<31>")
	)
	(segment
		(start 36.733226 -195.373498)
		(end 36.490148 -195.616576)
		(width 0.18288)
		(layer "In6.Cu")
		(net "M_C_CPU1_SB_DQ<31>")
	)
	(segment
		(start 82.570828 -219.03055)
		(end 73.772268 -210.23199)
		(width 0.18288)
		(layer "In6.Cu")
		(net "M_C_CPU1_SB_DQ<31>")
	)
	(segment
		(start 43.28668 -193.908172)
		(end 43.1038 -193.725292)
		(width 0.18288)
		(layer "In6.Cu")
		(net "M_C_CPU1_SB_DQ<31>")
	)
	(segment
		(start 93.688662 -225.217482)
		(end 93.688662 -225.203258)
		(width 0.088646)
		(layer "In6.Cu")
		(net "M_C_CPU1_SB_DQ<31>")
	)
	(segment
		(start 43.97756 -194.118484)
		(end 43.79468 -194.301364)
		(width 0.18288)
		(layer "In6.Cu")
		(net "M_C_CPU1_SB_DQ<31>")
	)
	(segment
		(start 41.04513 -194.358006)
		(end 40.71747 -194.358006)
		(width 0.18288)
		(layer "In6.Cu")
		(net "M_C_CPU1_SB_DQ<31>")
	)
	(segment
		(start 84.760562 -221.76486)
		(end 83.06816 -220.072458)
		(width 0.088646)
		(layer "In6.Cu")
		(net "M_C_CPU1_SB_DQ<31>")
	)
	(segment
		(start 93.040454 -224.070164)
		(end 93.031564 -224.065084)
		(width 0.088646)
		(layer "In6.Cu")
		(net "M_C_CPU1_SB_DQ<31>")
	)
	(segment
		(start 93.219016 -224.404936)
		(end 93.219016 -224.389442)
		(width 0.088646)
		(layer "In6.Cu")
		(net "M_C_CPU1_SB_DQ<31>")
	)
	(segment
		(start 82.570828 -219.575126)
		(end 82.570828 -219.03055)
		(width 0.18288)
		(layer "In6.Cu")
		(net "M_C_CPU1_SB_DQ<31>")
	)
	(segment
		(start 90.777568 -224.065084)
		(end 90.768678 -224.070164)
		(width 0.088646)
		(layer "In6.Cu")
		(net "M_C_CPU1_SB_DQ<31>")
	)
	(segment
		(start 36.958016 -194.331336)
		(end 36.733226 -194.556126)
		(width 0.18288)
		(layer "In6.Cu")
		(net "M_C_CPU1_SB_DQ<31>")
	)
	(segment
		(start 90.307414 -224.8789)
		(end 90.292682 -224.887536)
		(width 0.088646)
		(layer "In6.Cu")
		(net "M_C_CPU1_SB_DQ<31>")
	)
	(segment
		(start 88.43645 -223.246442)
		(end 88.428068 -223.251268)
		(width 0.088646)
		(layer "In6.Cu")
		(net "M_C_CPU1_SB_DQ<31>")
	)
	(segment
		(start 41.22801 -194.175126)
		(end 41.04513 -194.358006)
		(width 0.18288)
		(layer "In6.Cu")
		(net "M_C_CPU1_SB_DQ<31>")
	)
	(segment
		(start 41.41089 -193.725292)
		(end 41.22801 -193.908172)
		(width 0.18288)
		(layer "In6.Cu")
		(net "M_C_CPU1_SB_DQ<31>")
	)
	(segment
		(start 40.71747 -194.358006)
		(end 40.53459 -194.175126)
		(width 0.18288)
		(layer "In6.Cu")
		(net "M_C_CPU1_SB_DQ<31>")
	)
	(segment
		(start 94.920054 -225.69805)
		(end 94.911164 -225.69297)
		(width 0.088646)
		(layer "In6.Cu")
		(net "M_C_CPU1_SB_DQ<31>")
	)
	(segment
		(start 63.46698 -197.718426)
		(end 62.57798 -196.829426)
		(width 0.18288)
		(layer "In6.Cu")
		(net "M_C_CPU1_SB_DQ<31>")
	)
	(segment
		(start 58.87339 -194.105784)
		(end 56.63057 -193.90614)
		(width 0.18288)
		(layer "In6.Cu")
		(net "M_C_CPU1_SB_DQ<31>")
	)
	(segment
		(start 90.31351 -224.875344)
		(end 90.307414 -224.8789)
		(width 0.088646)
		(layer "In6.Cu")
		(net "M_C_CPU1_SB_DQ<31>")
	)
	(segment
		(start 40.53459 -194.175126)
		(end 40.53459 -193.908172)
		(width 0.18288)
		(layer "In6.Cu")
		(net "M_C_CPU1_SB_DQ<31>")
	)
	(segment
		(start 95.946468 -226.506786)
		(end 95.936054 -226.512882)
		(width 0.088646)
		(layer "In6.Cu")
		(net "M_C_CPU1_SB_DQ<31>")
	)
	(segment
		(start 91.339416 -224.404936)
		(end 91.339416 -224.389442)
		(width 0.088646)
		(layer "In6.Cu")
		(net "M_C_CPU1_SB_DQ<31>")
	)
	(segment
		(start 36.733226 -194.556126)
		(end 36.733226 -195.373498)
		(width 0.18288)
		(layer "In6.Cu")
		(net "M_C_CPU1_SB_DQ<31>")
	)
	(segment
		(start 92.19311 -224.875344)
		(end 92.187014 -224.8789)
		(width 0.088646)
		(layer "In6.Cu")
		(net "M_C_CPU1_SB_DQ<31>")
	)
	(segment
		(start 39.57066 -193.725292)
		(end 39.291006 -193.75755)
		(width 0.18288)
		(layer "In6.Cu")
		(net "M_C_CPU1_SB_DQ<31>")
	)
	(segment
		(start 36.490148 -195.616576)
		(end 35.976814 -195.616576)
		(width 0.18288)
		(layer "In6.Cu")
		(net "M_C_CPU1_SB_DQ<31>")
	)
	(segment
		(start 65.85712 -199.247252)
		(end 64.328294 -197.718426)
		(width 0.18288)
		(layer "In6.Cu")
		(net "M_C_CPU1_SB_DQ<31>")
	)
	(arc
		(start 95.38081 -226.506786)
		(mid 95.177987 -226.306555)
		(end 95.098616 -226.032822)
		(width 0.088646)
		(layer "In6.Cu")
		(net "M_C_CPU1_SB_DQ<31>")
	)
	(arc
		(start 85.608668 -223.251268)
		(mid 85.334439 -223.327193)
		(end 85.057996 -223.259904)
		(width 0.088646)
		(layer "In6.Cu")
		(net "M_C_CPU1_SB_DQ<31>")
	)
	(arc
		(start 97.26041 -227.155502)
		(mid 97.073212 -227.205645)
		(end 96.886014 -227.155502)
		(width 0.088646)
		(layer "In6.Cu")
		(net "M_C_CPU1_SB_DQ<31>")
	)
	(arc
		(start 89.74201 -224.8789)
		(mid 89.539187 -224.678669)
		(end 89.459816 -224.404936)
		(width 0.088646)
		(layer "In6.Cu")
		(net "M_C_CPU1_SB_DQ<31>")
	)
	(arc
		(start 90.590116 -224.389442)
		(mid 90.516125 -224.669008)
		(end 90.31351 -224.875344)
		(width 0.088646)
		(layer "In6.Cu")
		(net "M_C_CPU1_SB_DQ<31>")
	)
	(arc
		(start 88.989662 -223.575626)
		(mid 88.941983 -223.392726)
		(end 88.8111 -223.256348)
		(width 0.088646)
		(layer "In6.Cu")
		(net "M_C_CPU1_SB_DQ<31>")
	)
	(arc
		(start 88.413336 -223.259904)
		(mid 88.136895 -223.32707)
		(end 87.862664 -223.251268)
		(width 0.088646)
		(layer "In6.Cu")
		(net "M_C_CPU1_SB_DQ<31>")
	)
	(arc
		(start 89.459816 -224.389442)
		(mid 89.412137 -224.206542)
		(end 89.281254 -224.070164)
		(width 0.088646)
		(layer "In6.Cu")
		(net "M_C_CPU1_SB_DQ<31>")
	)
	(arc
		(start 96.320864 -226.506786)
		(mid 96.133666 -226.456643)
		(end 95.946468 -226.506786)
		(width 0.088646)
		(layer "In6.Cu")
		(net "M_C_CPU1_SB_DQ<31>")
	)
	(arc
		(start 89.260172 -224.057972)
		(mid 89.061944 -223.852124)
		(end 88.989662 -223.575626)
		(width 0.088646)
		(layer "In6.Cu")
		(net "M_C_CPU1_SB_DQ<31>")
	)
	(arc
		(start 96.564704 -226.750372)
		(mid 96.458818 -226.612526)
		(end 96.320864 -226.506786)
		(width 0.088646)
		(layer "In6.Cu")
		(net "M_C_CPU1_SB_DQ<31>")
	)
	(arc
		(start 88.80221 -223.251268)
		(mid 88.619959 -223.201157)
		(end 88.43645 -223.246442)
		(width 0.088646)
		(layer "In6.Cu")
		(net "M_C_CPU1_SB_DQ<31>")
	)
	(arc
		(start 93.971364 -225.69297)
		(mid 93.767883 -225.492166)
		(end 93.688662 -225.217482)
		(width 0.088646)
		(layer "In6.Cu")
		(net "M_C_CPU1_SB_DQ<31>")
	)
	(arc
		(start 95.936054 -226.512882)
		(mid 95.657622 -226.582728)
		(end 95.38081 -226.506786)
		(width 0.088646)
		(layer "In6.Cu")
		(net "M_C_CPU1_SB_DQ<31>")
	)
	(arc
		(start 86.548468 -223.251268)
		(mid 86.265766 -223.32701)
		(end 85.983064 -223.251268)
		(width 0.088646)
		(layer "In6.Cu")
		(net "M_C_CPU1_SB_DQ<31>")
	)
	(arc
		(start 94.911164 -225.69297)
		(mid 94.723966 -225.642827)
		(end 94.536768 -225.69297)
		(width 0.088646)
		(layer "In6.Cu")
		(net "M_C_CPU1_SB_DQ<31>")
	)
	(arc
		(start 91.151964 -224.065084)
		(mid 90.964766 -224.014941)
		(end 90.777568 -224.065084)
		(width 0.088646)
		(layer "In6.Cu")
		(net "M_C_CPU1_SB_DQ<31>")
	)
	(arc
		(start 93.219016 -224.389442)
		(mid 93.171337 -224.206542)
		(end 93.040454 -224.070164)
		(width 0.088646)
		(layer "In6.Cu")
		(net "M_C_CPU1_SB_DQ<31>")
	)
	(arc
		(start 94.536768 -225.69297)
		(mid 94.262539 -225.768895)
		(end 93.986096 -225.701606)
		(width 0.088646)
		(layer "In6.Cu")
		(net "M_C_CPU1_SB_DQ<31>")
	)
	(arc
		(start 93.688662 -225.203258)
		(mid 93.640983 -225.020358)
		(end 93.5101 -224.88398)
		(width 0.088646)
		(layer "In6.Cu")
		(net "M_C_CPU1_SB_DQ<31>")
	)
	(arc
		(start 93.50121 -224.8789)
		(mid 93.298387 -224.678669)
		(end 93.219016 -224.404936)
		(width 0.088646)
		(layer "In6.Cu")
		(net "M_C_CPU1_SB_DQ<31>")
	)
	(arc
		(start 92.648278 -224.070164)
		(mid 92.517364 -224.206524)
		(end 92.469716 -224.389442)
		(width 0.088646)
		(layer "In6.Cu")
		(net "M_C_CPU1_SB_DQ<31>")
	)
	(arc
		(start 87.862664 -223.251268)
		(mid 87.675466 -223.201125)
		(end 87.488268 -223.251268)
		(width 0.088646)
		(layer "In6.Cu")
		(net "M_C_CPU1_SB_DQ<31>")
	)
	(arc
		(start 96.79305 -227.101146)
		(mid 96.757974 -227.073952)
		(end 96.731074 -227.038662)
		(width 0.088646)
		(layer "In6.Cu")
		(net "M_C_CPU1_SB_DQ<31>")
	)
	(arc
		(start 90.768678 -224.070164)
		(mid 90.637764 -224.206524)
		(end 90.590116 -224.389442)
		(width 0.088646)
		(layer "In6.Cu")
		(net "M_C_CPU1_SB_DQ<31>")
	)
	(arc
		(start 86.922864 -223.251268)
		(mid 86.735666 -223.201125)
		(end 86.548468 -223.251268)
		(width 0.088646)
		(layer "In6.Cu")
		(net "M_C_CPU1_SB_DQ<31>")
	)
	(arc
		(start 85.983064 -223.251268)
		(mid 85.795866 -223.201125)
		(end 85.608668 -223.251268)
		(width 0.088646)
		(layer "In6.Cu")
		(net "M_C_CPU1_SB_DQ<31>")
	)
	(arc
		(start 98.013012 -226.831144)
		(mid 97.828943 -226.855368)
		(end 97.657412 -226.926394)
		(width 0.088646)
		(layer "In6.Cu")
		(net "M_C_CPU1_SB_DQ<31>")
	)
	(arc
		(start 95.098616 -226.017328)
		(mid 95.050937 -225.834428)
		(end 94.920054 -225.69805)
		(width 0.088646)
		(layer "In6.Cu")
		(net "M_C_CPU1_SB_DQ<31>")
	)
	(arc
		(start 85.043264 -223.251268)
		(mid 84.839783 -223.050464)
		(end 84.760562 -222.77578)
		(width 0.088646)
		(layer "In6.Cu")
		(net "M_C_CPU1_SB_DQ<31>")
	)
	(arc
		(start 91.62161 -224.8789)
		(mid 91.418787 -224.678669)
		(end 91.339416 -224.404936)
		(width 0.088646)
		(layer "In6.Cu")
		(net "M_C_CPU1_SB_DQ<31>")
	)
	(arc
		(start 91.339416 -224.389442)
		(mid 91.291737 -224.206542)
		(end 91.160854 -224.070164)
		(width 0.088646)
		(layer "In6.Cu")
		(net "M_C_CPU1_SB_DQ<31>")
	)
	(arc
		(start 93.031564 -224.065084)
		(mid 92.844366 -224.014941)
		(end 92.657168 -224.065084)
		(width 0.088646)
		(layer "In6.Cu")
		(net "M_C_CPU1_SB_DQ<31>")
	)
	(arc
		(start 92.172282 -224.887536)
		(mid 91.895807 -224.954856)
		(end 91.62161 -224.8789)
		(width 0.088646)
		(layer "In6.Cu")
		(net "M_C_CPU1_SB_DQ<31>")
	)
	(arc
		(start 90.292682 -224.887536)
		(mid 90.016207 -224.954856)
		(end 89.74201 -224.8789)
		(width 0.088646)
		(layer "In6.Cu")
		(net "M_C_CPU1_SB_DQ<31>")
	)
	(arc
		(start 92.469716 -224.389442)
		(mid 92.395725 -224.669008)
		(end 92.19311 -224.875344)
		(width 0.088646)
		(layer "In6.Cu")
		(net "M_C_CPU1_SB_DQ<31>")
	)
	(arc
		(start 87.488268 -223.251268)
		(mid 87.205566 -223.32701)
		(end 86.922864 -223.251268)
		(width 0.088646)
		(layer "In6.Cu")
		(net "M_C_CPU1_SB_DQ<31>")
	)
	(segment
		(start 35.976814 -197.316598)
		(end 34.871914 -197.316598)
		(width 0.20066)
		(layer "F.Cu")
		(net "M_C_CPU1_SB_DQ<30>")
	)
	(segment
		(start 28.475178 -197.316598)
		(end 28.91028 -196.881496)
		(width 0.20066)
		(layer "F.Cu")
		(net "M_C_CPU1_SB_DQ<30>")
	)
	(segment
		(start 33.345374 -197.528434)
		(end 33.55721 -197.316598)
		(width 0.20066)
		(layer "F.Cu")
		(net "M_C_CPU1_SB_DQ<30>")
	)
	(segment
		(start 32.74949 -197.03542)
		(end 32.74949 -197.361048)
		(width 0.20066)
		(layer "F.Cu")
		(net "M_C_CPU1_SB_DQ<30>")
	)
	(segment
		(start 95.193866 -227.367084)
		(end 95.193612 -227.36683)
		(width 0.20066)
		(layer "F.Cu")
		(net "M_C_CPU1_SB_DQ<30>")
	)
	(segment
		(start 29.657802 -196.891656)
		(end 29.912818 -196.891656)
		(width 0.101854)
		(layer "F.Cu")
		(net "M_C_CPU1_SB_DQ<30>")
	)
	(segment
		(start 29.912818 -196.891656)
		(end 31.972758 -196.891656)
		(width 0.1016)
		(layer "F.Cu")
		(net "M_C_CPU1_SB_DQ<30>")
	)
	(segment
		(start 32.605726 -196.891656)
		(end 32.74949 -197.03542)
		(width 0.20066)
		(layer "F.Cu")
		(net "M_C_CPU1_SB_DQ<30>")
	)
	(segment
		(start 27.328114 -197.316598)
		(end 28.475178 -197.316598)
		(width 0.20066)
		(layer "F.Cu")
		(net "M_C_CPU1_SB_DQ<30>")
	)
	(segment
		(start 32.74949 -197.361048)
		(end 32.916876 -197.528434)
		(width 0.20066)
		(layer "F.Cu")
		(net "M_C_CPU1_SB_DQ<30>")
	)
	(segment
		(start 29.647642 -196.881496)
		(end 29.657802 -196.891656)
		(width 0.101854)
		(layer "F.Cu")
		(net "M_C_CPU1_SB_DQ<30>")
	)
	(segment
		(start 31.972758 -196.891656)
		(end 32.605726 -196.891656)
		(width 0.20066)
		(layer "F.Cu")
		(net "M_C_CPU1_SB_DQ<30>")
	)
	(segment
		(start 95.193612 -227.36683)
		(end 95.193612 -226.831144)
		(width 0.20066)
		(layer "F.Cu")
		(net "M_C_CPU1_SB_DQ<30>")
	)
	(segment
		(start 28.91028 -196.881496)
		(end 29.647642 -196.881496)
		(width 0.20066)
		(layer "F.Cu")
		(net "M_C_CPU1_SB_DQ<30>")
	)
	(segment
		(start 33.55721 -197.316598)
		(end 34.871914 -197.316598)
		(width 0.20066)
		(layer "F.Cu")
		(net "M_C_CPU1_SB_DQ<30>")
	)
	(segment
		(start 32.916876 -197.528434)
		(end 33.345374 -197.528434)
		(width 0.20066)
		(layer "F.Cu")
		(net "M_C_CPU1_SB_DQ<30>")
	)
	(segment
		(start 88.897968 -224.7138)
		(end 88.889078 -224.70872)
		(width 0.088646)
		(layer "In6.Cu")
		(net "M_C_CPU1_SB_DQ<30>")
	)
	(segment
		(start 35.976814 -197.24243)
		(end 35.976814 -197.316598)
		(width 0.18288)
		(layer "In6.Cu")
		(net "M_C_CPU1_SB_DQ<30>")
	)
	(segment
		(start 82.296762 -221.047818)
		(end 82.054446 -220.805502)
		(width 0.18288)
		(layer "In6.Cu")
		(net "M_C_CPU1_SB_DQ<30>")
	)
	(segment
		(start 57.245758 -194.607688)
		(end 57.062878 -194.790568)
		(width 0.18288)
		(layer "In6.Cu")
		(net "M_C_CPU1_SB_DQ<30>")
	)
	(segment
		(start 57.570878 -194.607688)
		(end 57.245758 -194.607688)
		(width 0.18288)
		(layer "In6.Cu")
		(net "M_C_CPU1_SB_DQ<30>")
	)
	(segment
		(start 42.631106 -194.458336)
		(end 42.448226 -194.275456)
		(width 0.18288)
		(layer "In6.Cu")
		(net "M_C_CPU1_SB_DQ<30>")
	)
	(segment
		(start 84.677504 -223.90481)
		(end 84.669122 -223.899984)
		(width 0.088646)
		(layer "In6.Cu")
		(net "M_C_CPU1_SB_DQ<30>")
	)
	(segment
		(start 57.936638 -195.432426)
		(end 57.753758 -195.249546)
		(width 0.18288)
		(layer "In6.Cu")
		(net "M_C_CPU1_SB_DQ<30>")
	)
	(segment
		(start 57.753758 -194.790568)
		(end 57.570878 -194.607688)
		(width 0.18288)
		(layer "In6.Cu")
		(net "M_C_CPU1_SB_DQ<30>")
	)
	(segment
		(start 57.753758 -195.249546)
		(end 57.753758 -194.790568)
		(width 0.18288)
		(layer "In6.Cu")
		(net "M_C_CPU1_SB_DQ<30>")
	)
	(segment
		(start 55.061358 -194.443858)
		(end 54.565804 -194.238626)
		(width 0.18288)
		(layer "In6.Cu")
		(net "M_C_CPU1_SB_DQ<30>")
	)
	(segment
		(start 58.970926 -195.432426)
		(end 57.936638 -195.432426)
		(width 0.18288)
		(layer "In6.Cu")
		(net "M_C_CPU1_SB_DQ<30>")
	)
	(segment
		(start 88.427814 -223.899984)
		(end 88.4174 -223.893888)
		(width 0.088646)
		(layer "In6.Cu")
		(net "M_C_CPU1_SB_DQ<30>")
	)
	(segment
		(start 82.479642 -221.047818)
		(end 82.296762 -221.047818)
		(width 0.18288)
		(layer "In6.Cu")
		(net "M_C_CPU1_SB_DQ<30>")
	)
	(segment
		(start 95.193612 -226.831144)
		(end 94.880938 -226.831144)
		(width 0.088646)
		(layer "In6.Cu")
		(net "M_C_CPU1_SB_DQ<30>")
	)
	(segment
		(start 37.050218 -196.169026)
		(end 35.976814 -197.24243)
		(width 0.18288)
		(layer "In6.Cu")
		(net "M_C_CPU1_SB_DQ<30>")
	)
	(segment
		(start 37.302694 -196.169026)
		(end 37.050218 -196.169026)
		(width 0.18288)
		(layer "In6.Cu")
		(net "M_C_CPU1_SB_DQ<30>")
	)
	(segment
		(start 42.631106 -195.16979)
		(end 42.631106 -194.458336)
		(width 0.18288)
		(layer "In6.Cu")
		(net "M_C_CPU1_SB_DQ<30>")
	)
	(segment
		(start 90.307414 -225.527616)
		(end 90.292682 -225.51898)
		(width 0.088646)
		(layer "In6.Cu")
		(net "M_C_CPU1_SB_DQ<30>")
	)
	(segment
		(start 61.917072 -197.845426)
		(end 60.297822 -196.226176)
		(width 0.18288)
		(layer "In6.Cu")
		(net "M_C_CPU1_SB_DQ<30>")
	)
	(segment
		(start 40.841422 -195.127626)
		(end 40.1066 -195.127626)
		(width 0.18288)
		(layer "In6.Cu")
		(net "M_C_CPU1_SB_DQ<30>")
	)
	(segment
		(start 39.74084 -194.314064)
		(end 39.157656 -194.314064)
		(width 0.18288)
		(layer "In6.Cu")
		(net "M_C_CPU1_SB_DQ<30>")
	)
	(segment
		(start 38.602666 -195.949062)
		(end 38.370764 -196.180964)
		(width 0.18288)
		(layer "In6.Cu")
		(net "M_C_CPU1_SB_DQ<30>")
	)
	(segment
		(start 39.92372 -194.496944)
		(end 39.74084 -194.314064)
		(width 0.18288)
		(layer "In6.Cu")
		(net "M_C_CPU1_SB_DQ<30>")
	)
	(segment
		(start 84.011516 -222.084138)
		(end 82.975196 -221.047818)
		(width 0.088646)
		(layer "In6.Cu")
		(net "M_C_CPU1_SB_DQ<30>")
	)
	(segment
		(start 44.16298 -195.190872)
		(end 44.001182 -195.35267)
		(width 0.18288)
		(layer "In6.Cu")
		(net "M_C_CPU1_SB_DQ<30>")
	)
	(segment
		(start 45.02658 -195.190872)
		(end 44.16298 -195.190872)
		(width 0.18288)
		(layer "In6.Cu")
		(net "M_C_CPU1_SB_DQ<30>")
	)
	(segment
		(start 38.602666 -195.69049)
		(end 38.602666 -195.949062)
		(width 0.18288)
		(layer "In6.Cu")
		(net "M_C_CPU1_SB_DQ<30>")
	)
	(segment
		(start 56.879998 -195.432426)
		(end 56.049926 -195.432426)
		(width 0.18288)
		(layer "In6.Cu")
		(net "M_C_CPU1_SB_DQ<30>")
	)
	(segment
		(start 38.321234 -195.409058)
		(end 38.602666 -195.69049)
		(width 0.18288)
		(layer "In6.Cu")
		(net "M_C_CPU1_SB_DQ<30>")
	)
	(segment
		(start 85.057996 -223.891348)
		(end 85.043264 -223.899984)
		(width 0.088646)
		(layer "In6.Cu")
		(net "M_C_CPU1_SB_DQ<30>")
	)
	(segment
		(start 64.633094 -198.734426)
		(end 63.441326 -198.734426)
		(width 0.18288)
		(layer "In6.Cu")
		(net "M_C_CPU1_SB_DQ<30>")
	)
	(segment
		(start 38.370764 -196.180964)
		(end 38.112192 -196.180964)
		(width 0.18288)
		(layer "In6.Cu")
		(net "M_C_CPU1_SB_DQ<30>")
	)
	(segment
		(start 57.062878 -195.249546)
		(end 56.879998 -195.432426)
		(width 0.18288)
		(layer "In6.Cu")
		(net "M_C_CPU1_SB_DQ<30>")
	)
	(segment
		(start 42.123106 -194.275456)
		(end 41.940226 -194.458336)
		(width 0.18288)
		(layer "In6.Cu")
		(net "M_C_CPU1_SB_DQ<30>")
	)
	(segment
		(start 93.596968 -226.341686)
		(end 93.588078 -226.336606)
		(width 0.088646)
		(layer "In6.Cu")
		(net "M_C_CPU1_SB_DQ<30>")
	)
	(segment
		(start 65.65265 -199.753982)
		(end 64.633094 -198.734426)
		(width 0.18288)
		(layer "In6.Cu")
		(net "M_C_CPU1_SB_DQ<30>")
	)
	(segment
		(start 60.297822 -196.226176)
		(end 59.764676 -196.226176)
		(width 0.18288)
		(layer "In6.Cu")
		(net "M_C_CPU1_SB_DQ<30>")
	)
	(segment
		(start 62.552326 -197.845426)
		(end 61.917072 -197.845426)
		(width 0.18288)
		(layer "In6.Cu")
		(net "M_C_CPU1_SB_DQ<30>")
	)
	(segment
		(start 37.572188 -195.899532)
		(end 37.302694 -196.169026)
		(width 0.18288)
		(layer "In6.Cu")
		(net "M_C_CPU1_SB_DQ<30>")
	)
	(segment
		(start 39.92372 -194.944746)
		(end 39.92372 -194.496944)
		(width 0.18288)
		(layer "In6.Cu")
		(net "M_C_CPU1_SB_DQ<30>")
	)
	(segment
		(start 93.409516 -226.017328)
		(end 93.409516 -226.003104)
		(width 0.088646)
		(layer "In6.Cu")
		(net "M_C_CPU1_SB_DQ<30>")
	)
	(segment
		(start 41.940226 -194.458336)
		(end 41.940226 -195.16979)
		(width 0.18288)
		(layer "In6.Cu")
		(net "M_C_CPU1_SB_DQ<30>")
	)
	(segment
		(start 82.054446 -220.805502)
		(end 82.054446 -219.218256)
		(width 0.18288)
		(layer "In6.Cu")
		(net "M_C_CPU1_SB_DQ<30>")
	)
	(segment
		(start 39.157656 -194.314064)
		(end 38.321234 -195.150486)
		(width 0.18288)
		(layer "In6.Cu")
		(net "M_C_CPU1_SB_DQ<30>")
	)
	(segment
		(start 88.43391 -223.90354)
		(end 88.427814 -223.899984)
		(width 0.088646)
		(layer "In6.Cu")
		(net "M_C_CPU1_SB_DQ<30>")
	)
	(segment
		(start 41.940226 -195.16979)
		(end 41.757346 -195.35267)
		(width 0.18288)
		(layer "In6.Cu")
		(net "M_C_CPU1_SB_DQ<30>")
	)
	(segment
		(start 54.565804 -194.238626)
		(end 45.978826 -194.238626)
		(width 0.18288)
		(layer "In6.Cu")
		(net "M_C_CPU1_SB_DQ<30>")
	)
	(segment
		(start 41.066466 -195.35267)
		(end 40.841422 -195.127626)
		(width 0.18288)
		(layer "In6.Cu")
		(net "M_C_CPU1_SB_DQ<30>")
	)
	(segment
		(start 66.632582 -199.753982)
		(end 65.65265 -199.753982)
		(width 0.18288)
		(layer "In6.Cu")
		(net "M_C_CPU1_SB_DQ<30>")
	)
	(segment
		(start 70.450202 -203.571602)
		(end 66.632582 -199.753982)
		(width 0.18288)
		(layer "In6.Cu")
		(net "M_C_CPU1_SB_DQ<30>")
	)
	(segment
		(start 44.001182 -195.35267)
		(end 42.813986 -195.35267)
		(width 0.18288)
		(layer "In6.Cu")
		(net "M_C_CPU1_SB_DQ<30>")
	)
	(segment
		(start 82.975196 -221.047818)
		(end 82.479642 -221.047818)
		(width 0.088646)
		(layer "In6.Cu")
		(net "M_C_CPU1_SB_DQ<30>")
	)
	(segment
		(start 63.441326 -198.734426)
		(end 62.552326 -197.845426)
		(width 0.18288)
		(layer "In6.Cu")
		(net "M_C_CPU1_SB_DQ<30>")
	)
	(segment
		(start 45.978826 -194.238626)
		(end 45.02658 -195.190872)
		(width 0.18288)
		(layer "In6.Cu")
		(net "M_C_CPU1_SB_DQ<30>")
	)
	(segment
		(start 84.591144 -223.840548)
		(end 84.011516 -223.26092)
		(width 0.088646)
		(layer "In6.Cu")
		(net "M_C_CPU1_SB_DQ<30>")
	)
	(segment
		(start 89.180416 -225.211894)
		(end 89.180416 -225.193352)
		(width 0.088646)
		(layer "In6.Cu")
		(net "M_C_CPU1_SB_DQ<30>")
	)
	(segment
		(start 40.1066 -195.127626)
		(end 39.92372 -194.944746)
		(width 0.18288)
		(layer "In6.Cu")
		(net "M_C_CPU1_SB_DQ<30>")
	)
	(segment
		(start 42.813986 -195.35267)
		(end 42.631106 -195.16979)
		(width 0.18288)
		(layer "In6.Cu")
		(net "M_C_CPU1_SB_DQ<30>")
	)
	(segment
		(start 57.062878 -194.790568)
		(end 57.062878 -195.249546)
		(width 0.18288)
		(layer "In6.Cu")
		(net "M_C_CPU1_SB_DQ<30>")
	)
	(segment
		(start 93.986096 -226.33305)
		(end 93.971364 -226.341686)
		(width 0.088646)
		(layer "In6.Cu")
		(net "M_C_CPU1_SB_DQ<30>")
	)
	(segment
		(start 41.757346 -195.35267)
		(end 41.066466 -195.35267)
		(width 0.18288)
		(layer "In6.Cu")
		(net "M_C_CPU1_SB_DQ<30>")
	)
	(segment
		(start 37.83076 -195.899532)
		(end 37.572188 -195.899532)
		(width 0.18288)
		(layer "In6.Cu")
		(net "M_C_CPU1_SB_DQ<30>")
	)
	(segment
		(start 42.448226 -194.275456)
		(end 42.123106 -194.275456)
		(width 0.18288)
		(layer "In6.Cu")
		(net "M_C_CPU1_SB_DQ<30>")
	)
	(segment
		(start 93.126814 -225.527616)
		(end 93.112082 -225.51898)
		(width 0.088646)
		(layer "In6.Cu")
		(net "M_C_CPU1_SB_DQ<30>")
	)
	(segment
		(start 84.011516 -223.26092)
		(end 84.011516 -222.084138)
		(width 0.088646)
		(layer "In6.Cu")
		(net "M_C_CPU1_SB_DQ<30>")
	)
	(segment
		(start 94.880938 -226.831144)
		(end 94.815406 -226.765612)
		(width 0.088646)
		(layer "In6.Cu")
		(net "M_C_CPU1_SB_DQ<30>")
	)
	(segment
		(start 92.187014 -225.527616)
		(end 92.172282 -225.51898)
		(width 0.088646)
		(layer "In6.Cu")
		(net "M_C_CPU1_SB_DQ<30>")
	)
	(segment
		(start 56.049926 -195.432426)
		(end 55.061358 -194.443858)
		(width 0.18288)
		(layer "In6.Cu")
		(net "M_C_CPU1_SB_DQ<30>")
	)
	(segment
		(start 38.112192 -196.180964)
		(end 37.83076 -195.899532)
		(width 0.18288)
		(layer "In6.Cu")
		(net "M_C_CPU1_SB_DQ<30>")
	)
	(segment
		(start 59.764676 -196.226176)
		(end 58.970926 -195.432426)
		(width 0.18288)
		(layer "In6.Cu")
		(net "M_C_CPU1_SB_DQ<30>")
	)
	(segment
		(start 38.321234 -195.150486)
		(end 38.321234 -195.409058)
		(width 0.18288)
		(layer "In6.Cu")
		(net "M_C_CPU1_SB_DQ<30>")
	)
	(segment
		(start 82.054446 -219.218256)
		(end 73.308718 -210.472528)
		(width 0.18288)
		(layer "In6.Cu")
		(net "M_C_CPU1_SB_DQ<30>")
	)
	(segment
		(start 73.308718 -210.472528)
		(end 70.450202 -203.571602)
		(width 0.18288)
		(layer "In6.Cu")
		(net "M_C_CPU1_SB_DQ<30>")
	)
	(arc
		(start 92.56141 -225.527616)
		(mid 92.374212 -225.577759)
		(end 92.187014 -225.527616)
		(width 0.088646)
		(layer "In6.Cu")
		(net "M_C_CPU1_SB_DQ<30>")
	)
	(arc
		(start 86.548468 -223.899984)
		(mid 86.265766 -223.824208)
		(end 85.983064 -223.899984)
		(width 0.088646)
		(layer "In6.Cu")
		(net "M_C_CPU1_SB_DQ<30>")
	)
	(arc
		(start 89.180416 -225.193352)
		(mid 89.102305 -224.916403)
		(end 88.897968 -224.7138)
		(width 0.088646)
		(layer "In6.Cu")
		(net "M_C_CPU1_SB_DQ<30>")
	)
	(arc
		(start 93.588078 -226.336606)
		(mid 93.457164 -226.200246)
		(end 93.409516 -226.017328)
		(width 0.088646)
		(layer "In6.Cu")
		(net "M_C_CPU1_SB_DQ<30>")
	)
	(arc
		(start 87.862664 -223.899984)
		(mid 87.675466 -223.950127)
		(end 87.488268 -223.899984)
		(width 0.088646)
		(layer "In6.Cu")
		(net "M_C_CPU1_SB_DQ<30>")
	)
	(arc
		(start 85.043264 -223.899984)
		(mid 84.861013 -223.950095)
		(end 84.677504 -223.90481)
		(width 0.088646)
		(layer "In6.Cu")
		(net "M_C_CPU1_SB_DQ<30>")
	)
	(arc
		(start 90.68181 -225.527616)
		(mid 90.494612 -225.577759)
		(end 90.307414 -225.527616)
		(width 0.088646)
		(layer "In6.Cu")
		(net "M_C_CPU1_SB_DQ<30>")
	)
	(arc
		(start 94.536768 -226.341686)
		(mid 94.262569 -226.265851)
		(end 93.986096 -226.33305)
		(width 0.088646)
		(layer "In6.Cu")
		(net "M_C_CPU1_SB_DQ<30>")
	)
	(arc
		(start 89.74201 -225.527616)
		(mid 89.554812 -225.577759)
		(end 89.367614 -225.527616)
		(width 0.088646)
		(layer "In6.Cu")
		(net "M_C_CPU1_SB_DQ<30>")
	)
	(arc
		(start 93.112082 -225.51898)
		(mid 92.835641 -225.451814)
		(end 92.56141 -225.527616)
		(width 0.088646)
		(layer "In6.Cu")
		(net "M_C_CPU1_SB_DQ<30>")
	)
	(arc
		(start 88.889078 -224.70872)
		(mid 88.758164 -224.57236)
		(end 88.710516 -224.389442)
		(width 0.088646)
		(layer "In6.Cu")
		(net "M_C_CPU1_SB_DQ<30>")
	)
	(arc
		(start 93.971364 -226.341686)
		(mid 93.784166 -226.391829)
		(end 93.596968 -226.341686)
		(width 0.088646)
		(layer "In6.Cu")
		(net "M_C_CPU1_SB_DQ<30>")
	)
	(arc
		(start 87.488268 -223.899984)
		(mid 87.205566 -223.824208)
		(end 86.922864 -223.899984)
		(width 0.088646)
		(layer "In6.Cu")
		(net "M_C_CPU1_SB_DQ<30>")
	)
	(arc
		(start 91.62161 -225.527616)
		(mid 91.434412 -225.577759)
		(end 91.247214 -225.527616)
		(width 0.088646)
		(layer "In6.Cu")
		(net "M_C_CPU1_SB_DQ<30>")
	)
	(arc
		(start 88.4174 -223.893888)
		(mid 88.139222 -223.824165)
		(end 87.862664 -223.899984)
		(width 0.088646)
		(layer "In6.Cu")
		(net "M_C_CPU1_SB_DQ<30>")
	)
	(arc
		(start 94.815406 -226.765612)
		(mid 94.726318 -226.520627)
		(end 94.536768 -226.341686)
		(width 0.088646)
		(layer "In6.Cu")
		(net "M_C_CPU1_SB_DQ<30>")
	)
	(arc
		(start 89.367614 -225.527616)
		(mid 89.232681 -225.394262)
		(end 89.180416 -225.211894)
		(width 0.088646)
		(layer "In6.Cu")
		(net "M_C_CPU1_SB_DQ<30>")
	)
	(arc
		(start 90.292682 -225.51898)
		(mid 90.016241 -225.451814)
		(end 89.74201 -225.527616)
		(width 0.088646)
		(layer "In6.Cu")
		(net "M_C_CPU1_SB_DQ<30>")
	)
	(arc
		(start 84.669122 -223.899984)
		(mid 84.628193 -223.872813)
		(end 84.591144 -223.840548)
		(width 0.088646)
		(layer "In6.Cu")
		(net "M_C_CPU1_SB_DQ<30>")
	)
	(arc
		(start 91.247214 -225.527616)
		(mid 90.964512 -225.451874)
		(end 90.68181 -225.527616)
		(width 0.088646)
		(layer "In6.Cu")
		(net "M_C_CPU1_SB_DQ<30>")
	)
	(arc
		(start 86.922864 -223.899984)
		(mid 86.735666 -223.950127)
		(end 86.548468 -223.899984)
		(width 0.088646)
		(layer "In6.Cu")
		(net "M_C_CPU1_SB_DQ<30>")
	)
	(arc
		(start 92.172282 -225.51898)
		(mid 91.895841 -225.451814)
		(end 91.62161 -225.527616)
		(width 0.088646)
		(layer "In6.Cu")
		(net "M_C_CPU1_SB_DQ<30>")
	)
	(arc
		(start 93.409516 -226.003104)
		(mid 93.330297 -225.728419)
		(end 93.126814 -225.527616)
		(width 0.088646)
		(layer "In6.Cu")
		(net "M_C_CPU1_SB_DQ<30>")
	)
	(arc
		(start 85.608668 -223.899984)
		(mid 85.334469 -223.824149)
		(end 85.057996 -223.891348)
		(width 0.088646)
		(layer "In6.Cu")
		(net "M_C_CPU1_SB_DQ<30>")
	)
	(arc
		(start 85.983064 -223.899984)
		(mid 85.795866 -223.950127)
		(end 85.608668 -223.899984)
		(width 0.088646)
		(layer "In6.Cu")
		(net "M_C_CPU1_SB_DQ<30>")
	)
	(arc
		(start 88.710516 -224.389442)
		(mid 88.636525 -224.109876)
		(end 88.43391 -223.90354)
		(width 0.088646)
		(layer "In6.Cu")
		(net "M_C_CPU1_SB_DQ<30>")
	)
	(segment
		(start 28.475178 -231.316784)
		(end 28.91028 -230.881682)
		(width 0.20066)
		(layer "F.Cu")
		(net "M_C_CPU1_SB_DQ<2>")
	)
	(segment
		(start 27.328114 -231.316784)
		(end 28.475178 -231.316784)
		(width 0.20066)
		(layer "F.Cu")
		(net "M_C_CPU1_SB_DQ<2>")
	)
	(segment
		(start 96.603312 -244.458744)
		(end 96.603566 -244.45849)
		(width 0.20066)
		(layer "F.Cu")
		(net "M_C_CPU1_SB_DQ<2>")
	)
	(segment
		(start 29.912818 -230.891842)
		(end 31.972758 -230.891842)
		(width 0.1016)
		(layer "F.Cu")
		(net "M_C_CPU1_SB_DQ<2>")
	)
	(segment
		(start 96.603566 -244.45849)
		(end 96.603566 -243.922804)
		(width 0.20066)
		(layer "F.Cu")
		(net "M_C_CPU1_SB_DQ<2>")
	)
	(segment
		(start 32.74949 -231.035606)
		(end 32.74949 -231.361234)
		(width 0.20066)
		(layer "F.Cu")
		(net "M_C_CPU1_SB_DQ<2>")
	)
	(segment
		(start 29.647642 -230.881682)
		(end 29.657802 -230.891842)
		(width 0.101854)
		(layer "F.Cu")
		(net "M_C_CPU1_SB_DQ<2>")
	)
	(segment
		(start 31.972758 -230.891842)
		(end 32.605726 -230.891842)
		(width 0.20066)
		(layer "F.Cu")
		(net "M_C_CPU1_SB_DQ<2>")
	)
	(segment
		(start 32.916876 -231.52862)
		(end 33.345374 -231.52862)
		(width 0.20066)
		(layer "F.Cu")
		(net "M_C_CPU1_SB_DQ<2>")
	)
	(segment
		(start 29.657802 -230.891842)
		(end 29.912818 -230.891842)
		(width 0.101854)
		(layer "F.Cu")
		(net "M_C_CPU1_SB_DQ<2>")
	)
	(segment
		(start 33.55721 -231.316784)
		(end 34.871914 -231.316784)
		(width 0.20066)
		(layer "F.Cu")
		(net "M_C_CPU1_SB_DQ<2>")
	)
	(segment
		(start 32.74949 -231.361234)
		(end 32.916876 -231.52862)
		(width 0.20066)
		(layer "F.Cu")
		(net "M_C_CPU1_SB_DQ<2>")
	)
	(segment
		(start 28.91028 -230.881682)
		(end 29.647642 -230.881682)
		(width 0.20066)
		(layer "F.Cu")
		(net "M_C_CPU1_SB_DQ<2>")
	)
	(segment
		(start 32.605726 -230.891842)
		(end 32.74949 -231.035606)
		(width 0.20066)
		(layer "F.Cu")
		(net "M_C_CPU1_SB_DQ<2>")
	)
	(segment
		(start 35.976814 -231.316784)
		(end 34.871914 -231.316784)
		(width 0.20066)
		(layer "F.Cu")
		(net "M_C_CPU1_SB_DQ<2>")
	)
	(segment
		(start 33.345374 -231.52862)
		(end 33.55721 -231.316784)
		(width 0.20066)
		(layer "F.Cu")
		(net "M_C_CPU1_SB_DQ<2>")
	)
	(segment
		(start 93.981778 -244.241066)
		(end 93.971364 -244.247162)
		(width 0.088646)
		(layer "In6.Cu")
		(net "M_C_CPU1_SB_DQ<2>")
	)
	(segment
		(start 87.402924 -244.241066)
		(end 87.39251 -244.247162)
		(width 0.088646)
		(layer "In6.Cu")
		(net "M_C_CPU1_SB_DQ<2>")
	)
	(segment
		(start 66.878708 -239.195356)
		(end 65.228724 -239.195356)
		(width 0.18288)
		(layer "In6.Cu")
		(net "M_C_CPU1_SB_DQ<2>")
	)
	(segment
		(start 93.046296 -244.238526)
		(end 93.031564 -244.247162)
		(width 0.088646)
		(layer "In6.Cu")
		(net "M_C_CPU1_SB_DQ<2>")
	)
	(segment
		(start 44.778676 -235.684822)
		(end 44.471844 -235.991654)
		(width 0.18288)
		(layer "In6.Cu")
		(net "M_C_CPU1_SB_DQ<2>")
	)
	(segment
		(start 62.832488 -237.936786)
		(end 59.256422 -237.936786)
		(width 0.18288)
		(layer "In6.Cu")
		(net "M_C_CPU1_SB_DQ<2>")
	)
	(segment
		(start 42.15638 -234.247436)
		(end 41.687496 -234.71632)
		(width 0.18288)
		(layer "In6.Cu")
		(net "M_C_CPU1_SB_DQ<2>")
	)
	(segment
		(start 53.645308 -236.427772)
		(end 53.462428 -236.244892)
		(width 0.18288)
		(layer "In6.Cu")
		(net "M_C_CPU1_SB_DQ<2>")
	)
	(segment
		(start 70.613524 -242.930172)
		(end 66.878708 -239.195356)
		(width 0.18288)
		(layer "In6.Cu")
		(net "M_C_CPU1_SB_DQ<2>")
	)
	(segment
		(start 45.162724 -235.684822)
		(end 44.778676 -235.684822)
		(width 0.18288)
		(layer "In6.Cu")
		(net "M_C_CPU1_SB_DQ<2>")
	)
	(segment
		(start 49.545494 -237.362746)
		(end 49.31537 -237.132622)
		(width 0.18288)
		(layer "In6.Cu")
		(net "M_C_CPU1_SB_DQ<2>")
	)
	(segment
		(start 88.347296 -244.238526)
		(end 88.332564 -244.247162)
		(width 0.088646)
		(layer "In6.Cu")
		(net "M_C_CPU1_SB_DQ<2>")
	)
	(segment
		(start 40.515032 -233.802428)
		(end 40.515032 -233.342434)
		(width 0.18288)
		(layer "In6.Cu")
		(net "M_C_CPU1_SB_DQ<2>")
	)
	(segment
		(start 38.371526 -231.867964)
		(end 36.527994 -231.867964)
		(width 0.18288)
		(layer "In6.Cu")
		(net "M_C_CPU1_SB_DQ<2>")
	)
	(segment
		(start 52.080668 -237.063026)
		(end 51.452018 -237.691676)
		(width 0.18288)
		(layer "In6.Cu")
		(net "M_C_CPU1_SB_DQ<2>")
	)
	(segment
		(start 83.089496 -243.966746)
		(end 82.663538 -243.966746)
		(width 0.18288)
		(layer "In6.Cu")
		(net "M_C_CPU1_SB_DQ<2>")
	)
	(segment
		(start 52.771548 -237.063026)
		(end 52.080668 -237.063026)
		(width 0.18288)
		(layer "In6.Cu")
		(net "M_C_CPU1_SB_DQ<2>")
	)
	(segment
		(start 84.009992 -243.966746)
		(end 83.089496 -243.966746)
		(width 0.088646)
		(layer "In6.Cu")
		(net "M_C_CPU1_SB_DQ<2>")
	)
	(segment
		(start 96.603312 -243.922804)
		(end 96.445578 -243.76507)
		(width 0.088646)
		(layer "In6.Cu")
		(net "M_C_CPU1_SB_DQ<2>")
	)
	(segment
		(start 91.166696 -244.238526)
		(end 91.151964 -244.247162)
		(width 0.088646)
		(layer "In6.Cu")
		(net "M_C_CPU1_SB_DQ<2>")
	)
	(segment
		(start 49.52111 -236.409992)
		(end 49.102772 -235.991654)
		(width 0.18288)
		(layer "In6.Cu")
		(net "M_C_CPU1_SB_DQ<2>")
	)
	(segment
		(start 58.382662 -237.063026)
		(end 53.828188 -237.063026)
		(width 0.18288)
		(layer "In6.Cu")
		(net "M_C_CPU1_SB_DQ<2>")
	)
	(segment
		(start 84.659724 -244.206014)
		(end 84.24926 -244.206014)
		(width 0.088646)
		(layer "In6.Cu")
		(net "M_C_CPU1_SB_DQ<2>")
	)
	(segment
		(start 53.137308 -236.244892)
		(end 52.954428 -236.427772)
		(width 0.18288)
		(layer "In6.Cu")
		(net "M_C_CPU1_SB_DQ<2>")
	)
	(segment
		(start 59.256422 -237.936786)
		(end 58.382662 -237.063026)
		(width 0.18288)
		(layer "In6.Cu")
		(net "M_C_CPU1_SB_DQ<2>")
	)
	(segment
		(start 52.954428 -236.427772)
		(end 52.954428 -236.880146)
		(width 0.18288)
		(layer "In6.Cu")
		(net "M_C_CPU1_SB_DQ<2>")
	)
	(segment
		(start 63.508128 -238.612426)
		(end 62.832488 -237.936786)
		(width 0.18288)
		(layer "In6.Cu")
		(net "M_C_CPU1_SB_DQ<2>")
	)
	(segment
		(start 39.584376 -232.411778)
		(end 38.91534 -232.411778)
		(width 0.18288)
		(layer "In6.Cu")
		(net "M_C_CPU1_SB_DQ<2>")
	)
	(segment
		(start 84.24926 -244.206014)
		(end 84.009992 -243.966746)
		(width 0.088646)
		(layer "In6.Cu")
		(net "M_C_CPU1_SB_DQ<2>")
	)
	(segment
		(start 65.228724 -239.195356)
		(end 64.645794 -238.612426)
		(width 0.18288)
		(layer "In6.Cu")
		(net "M_C_CPU1_SB_DQ<2>")
	)
	(segment
		(start 95.263716 -243.662962)
		(end 95.098362 -243.828316)
		(width 0.088646)
		(layer "In6.Cu")
		(net "M_C_CPU1_SB_DQ<2>")
	)
	(segment
		(start 49.31537 -237.132622)
		(end 49.31537 -236.87405)
		(width 0.18288)
		(layer "In6.Cu")
		(net "M_C_CPU1_SB_DQ<2>")
	)
	(segment
		(start 89.287096 -244.238526)
		(end 89.272364 -244.247162)
		(width 0.088646)
		(layer "In6.Cu")
		(net "M_C_CPU1_SB_DQ<2>")
	)
	(segment
		(start 95.749618 -243.47678)
		(end 95.713042 -243.47678)
		(width 0.088646)
		(layer "In6.Cu")
		(net "M_C_CPU1_SB_DQ<2>")
	)
	(segment
		(start 51.452018 -237.691676)
		(end 50.802794 -237.691676)
		(width 0.18288)
		(layer "In6.Cu")
		(net "M_C_CPU1_SB_DQ<2>")
	)
	(segment
		(start 42.704258 -235.991654)
		(end 42.176192 -235.463588)
		(width 0.18288)
		(layer "In6.Cu")
		(net "M_C_CPU1_SB_DQ<2>")
	)
	(segment
		(start 41.687496 -234.71632)
		(end 41.428924 -234.71632)
		(width 0.18288)
		(layer "In6.Cu")
		(net "M_C_CPU1_SB_DQ<2>")
	)
	(segment
		(start 82.663538 -243.966746)
		(end 81.626964 -242.930172)
		(width 0.18288)
		(layer "In6.Cu")
		(net "M_C_CPU1_SB_DQ<2>")
	)
	(segment
		(start 44.471844 -235.991654)
		(end 42.704258 -235.991654)
		(width 0.18288)
		(layer "In6.Cu")
		(net "M_C_CPU1_SB_DQ<2>")
	)
	(segment
		(start 49.31537 -236.87405)
		(end 49.52111 -236.66831)
		(width 0.18288)
		(layer "In6.Cu")
		(net "M_C_CPU1_SB_DQ<2>")
	)
	(segment
		(start 81.626964 -242.930172)
		(end 70.613524 -242.930172)
		(width 0.18288)
		(layer "In6.Cu")
		(net "M_C_CPU1_SB_DQ<2>")
	)
	(segment
		(start 64.645794 -238.612426)
		(end 63.508128 -238.612426)
		(width 0.18288)
		(layer "In6.Cu")
		(net "M_C_CPU1_SB_DQ<2>")
	)
	(segment
		(start 52.954428 -236.880146)
		(end 52.771548 -237.063026)
		(width 0.18288)
		(layer "In6.Cu")
		(net "M_C_CPU1_SB_DQ<2>")
	)
	(segment
		(start 49.52111 -236.66831)
		(end 49.52111 -236.409992)
		(width 0.18288)
		(layer "In6.Cu")
		(net "M_C_CPU1_SB_DQ<2>")
	)
	(segment
		(start 45.469556 -235.991654)
		(end 45.162724 -235.684822)
		(width 0.18288)
		(layer "In6.Cu")
		(net "M_C_CPU1_SB_DQ<2>")
	)
	(segment
		(start 53.645308 -236.880146)
		(end 53.645308 -236.427772)
		(width 0.18288)
		(layer "In6.Cu")
		(net "M_C_CPU1_SB_DQ<2>")
	)
	(segment
		(start 42.176192 -235.205016)
		(end 42.645076 -234.736132)
		(width 0.18288)
		(layer "In6.Cu")
		(net "M_C_CPU1_SB_DQ<2>")
	)
	(segment
		(start 40.515032 -233.342434)
		(end 39.584376 -232.411778)
		(width 0.18288)
		(layer "In6.Cu")
		(net "M_C_CPU1_SB_DQ<2>")
	)
	(segment
		(start 42.645076 -234.47756)
		(end 42.414952 -234.247436)
		(width 0.18288)
		(layer "In6.Cu")
		(net "M_C_CPU1_SB_DQ<2>")
	)
	(segment
		(start 50.009806 -237.15726)
		(end 49.804066 -237.362746)
		(width 0.18288)
		(layer "In6.Cu")
		(net "M_C_CPU1_SB_DQ<2>")
	)
	(segment
		(start 36.527994 -231.867964)
		(end 35.976814 -231.316784)
		(width 0.18288)
		(layer "In6.Cu")
		(net "M_C_CPU1_SB_DQ<2>")
	)
	(segment
		(start 53.828188 -237.063026)
		(end 53.645308 -236.880146)
		(width 0.18288)
		(layer "In6.Cu")
		(net "M_C_CPU1_SB_DQ<2>")
	)
	(segment
		(start 50.802794 -237.691676)
		(end 50.268378 -237.15726)
		(width 0.18288)
		(layer "In6.Cu")
		(net "M_C_CPU1_SB_DQ<2>")
	)
	(segment
		(start 42.645076 -234.736132)
		(end 42.645076 -234.47756)
		(width 0.18288)
		(layer "In6.Cu")
		(net "M_C_CPU1_SB_DQ<2>")
	)
	(segment
		(start 38.91534 -232.411778)
		(end 38.371526 -231.867964)
		(width 0.18288)
		(layer "In6.Cu")
		(net "M_C_CPU1_SB_DQ<2>")
	)
	(segment
		(start 49.804066 -237.362746)
		(end 49.545494 -237.362746)
		(width 0.18288)
		(layer "In6.Cu")
		(net "M_C_CPU1_SB_DQ<2>")
	)
	(segment
		(start 42.176192 -235.463588)
		(end 42.176192 -235.205016)
		(width 0.18288)
		(layer "In6.Cu")
		(net "M_C_CPU1_SB_DQ<2>")
	)
	(segment
		(start 49.102772 -235.991654)
		(end 45.469556 -235.991654)
		(width 0.18288)
		(layer "In6.Cu")
		(net "M_C_CPU1_SB_DQ<2>")
	)
	(segment
		(start 50.268378 -237.15726)
		(end 50.009806 -237.15726)
		(width 0.18288)
		(layer "In6.Cu")
		(net "M_C_CPU1_SB_DQ<2>")
	)
	(segment
		(start 96.603566 -243.922804)
		(end 96.603312 -243.922804)
		(width 0.088646)
		(layer "In6.Cu")
		(net "M_C_CPU1_SB_DQ<2>")
	)
	(segment
		(start 53.462428 -236.244892)
		(end 53.137308 -236.244892)
		(width 0.18288)
		(layer "In6.Cu")
		(net "M_C_CPU1_SB_DQ<2>")
	)
	(segment
		(start 95.098362 -243.828316)
		(end 95.098362 -243.922804)
		(width 0.088646)
		(layer "In6.Cu")
		(net "M_C_CPU1_SB_DQ<2>")
	)
	(segment
		(start 42.414952 -234.247436)
		(end 42.15638 -234.247436)
		(width 0.18288)
		(layer "In6.Cu")
		(net "M_C_CPU1_SB_DQ<2>")
	)
	(segment
		(start 94.9198 -244.242082)
		(end 94.91091 -244.247162)
		(width 0.088646)
		(layer "In6.Cu")
		(net "M_C_CPU1_SB_DQ<2>")
	)
	(segment
		(start 41.428924 -234.71632)
		(end 40.515032 -233.802428)
		(width 0.18288)
		(layer "In6.Cu")
		(net "M_C_CPU1_SB_DQ<2>")
	)
	(arc
		(start 88.897968 -244.247162)
		(mid 88.623769 -244.171327)
		(end 88.347296 -244.238526)
		(width 0.088646)
		(layer "In6.Cu")
		(net "M_C_CPU1_SB_DQ<2>")
	)
	(arc
		(start 94.536514 -244.247162)
		(mid 94.259955 -244.171419)
		(end 93.981778 -244.241066)
		(width 0.088646)
		(layer "In6.Cu")
		(net "M_C_CPU1_SB_DQ<2>")
	)
	(arc
		(start 87.39251 -244.247162)
		(mid 87.205312 -244.297305)
		(end 87.018114 -244.247162)
		(width 0.088646)
		(layer "In6.Cu")
		(net "M_C_CPU1_SB_DQ<2>")
	)
	(arc
		(start 96.445578 -243.76507)
		(mid 96.126269 -243.551714)
		(end 95.749618 -243.47678)
		(width 0.088646)
		(layer "In6.Cu")
		(net "M_C_CPU1_SB_DQ<2>")
	)
	(arc
		(start 87.958168 -244.247162)
		(mid 87.681355 -244.171292)
		(end 87.402924 -244.241066)
		(width 0.088646)
		(layer "In6.Cu")
		(net "M_C_CPU1_SB_DQ<2>")
	)
	(arc
		(start 92.091764 -244.247162)
		(mid 91.904566 -244.297305)
		(end 91.717368 -244.247162)
		(width 0.088646)
		(layer "In6.Cu")
		(net "M_C_CPU1_SB_DQ<2>")
	)
	(arc
		(start 92.657168 -244.247162)
		(mid 92.374466 -244.171386)
		(end 92.091764 -244.247162)
		(width 0.088646)
		(layer "In6.Cu")
		(net "M_C_CPU1_SB_DQ<2>")
	)
	(arc
		(start 93.031564 -244.247162)
		(mid 92.844366 -244.297305)
		(end 92.657168 -244.247162)
		(width 0.088646)
		(layer "In6.Cu")
		(net "M_C_CPU1_SB_DQ<2>")
	)
	(arc
		(start 89.837768 -244.247162)
		(mid 89.563569 -244.171327)
		(end 89.287096 -244.238526)
		(width 0.088646)
		(layer "In6.Cu")
		(net "M_C_CPU1_SB_DQ<2>")
	)
	(arc
		(start 90.212164 -244.247162)
		(mid 90.024966 -244.297305)
		(end 89.837768 -244.247162)
		(width 0.088646)
		(layer "In6.Cu")
		(net "M_C_CPU1_SB_DQ<2>")
	)
	(arc
		(start 85.51291 -244.247162)
		(mid 85.325712 -244.297305)
		(end 85.138514 -244.247162)
		(width 0.088646)
		(layer "In6.Cu")
		(net "M_C_CPU1_SB_DQ<2>")
	)
	(arc
		(start 95.098362 -243.922804)
		(mid 95.050683 -244.105704)
		(end 94.9198 -244.242082)
		(width 0.088646)
		(layer "In6.Cu")
		(net "M_C_CPU1_SB_DQ<2>")
	)
	(arc
		(start 91.717368 -244.247162)
		(mid 91.443169 -244.171327)
		(end 91.166696 -244.238526)
		(width 0.088646)
		(layer "In6.Cu")
		(net "M_C_CPU1_SB_DQ<2>")
	)
	(arc
		(start 90.777568 -244.247162)
		(mid 90.494866 -244.171386)
		(end 90.212164 -244.247162)
		(width 0.088646)
		(layer "In6.Cu")
		(net "M_C_CPU1_SB_DQ<2>")
	)
	(arc
		(start 86.078314 -244.247162)
		(mid 85.795612 -244.171386)
		(end 85.51291 -244.247162)
		(width 0.088646)
		(layer "In6.Cu")
		(net "M_C_CPU1_SB_DQ<2>")
	)
	(arc
		(start 91.151964 -244.247162)
		(mid 90.964766 -244.297305)
		(end 90.777568 -244.247162)
		(width 0.088646)
		(layer "In6.Cu")
		(net "M_C_CPU1_SB_DQ<2>")
	)
	(arc
		(start 87.018114 -244.247162)
		(mid 86.735412 -244.171386)
		(end 86.45271 -244.247162)
		(width 0.088646)
		(layer "In6.Cu")
		(net "M_C_CPU1_SB_DQ<2>")
	)
	(arc
		(start 88.332564 -244.247162)
		(mid 88.145366 -244.297305)
		(end 87.958168 -244.247162)
		(width 0.088646)
		(layer "In6.Cu")
		(net "M_C_CPU1_SB_DQ<2>")
	)
	(arc
		(start 86.45271 -244.247162)
		(mid 86.265512 -244.297305)
		(end 86.078314 -244.247162)
		(width 0.088646)
		(layer "In6.Cu")
		(net "M_C_CPU1_SB_DQ<2>")
	)
	(arc
		(start 95.713042 -243.47678)
		(mid 95.469858 -243.52517)
		(end 95.263716 -243.662962)
		(width 0.088646)
		(layer "In6.Cu")
		(net "M_C_CPU1_SB_DQ<2>")
	)
	(arc
		(start 85.138514 -244.247162)
		(mid 84.903709 -244.173174)
		(end 84.659724 -244.206014)
		(width 0.088646)
		(layer "In6.Cu")
		(net "M_C_CPU1_SB_DQ<2>")
	)
	(arc
		(start 93.971364 -244.247162)
		(mid 93.784166 -244.297305)
		(end 93.596968 -244.247162)
		(width 0.088646)
		(layer "In6.Cu")
		(net "M_C_CPU1_SB_DQ<2>")
	)
	(arc
		(start 93.596968 -244.247162)
		(mid 93.322769 -244.171327)
		(end 93.046296 -244.238526)
		(width 0.088646)
		(layer "In6.Cu")
		(net "M_C_CPU1_SB_DQ<2>")
	)
	(arc
		(start 94.91091 -244.247162)
		(mid 94.723712 -244.297305)
		(end 94.536514 -244.247162)
		(width 0.088646)
		(layer "In6.Cu")
		(net "M_C_CPU1_SB_DQ<2>")
	)
	(arc
		(start 89.272364 -244.247162)
		(mid 89.085166 -244.297305)
		(end 88.897968 -244.247162)
		(width 0.088646)
		(layer "In6.Cu")
		(net "M_C_CPU1_SB_DQ<2>")
	)
	(segment
		(start 28.198318 -196.041772)
		(end 28.529026 -196.041772)
		(width 0.101854)
		(layer "F.Cu")
		(net "M_C_CPU1_SB_DQ<29>")
	)
	(segment
		(start 25.432512 -196.195442)
		(end 25.595072 -196.032882)
		(width 0.20066)
		(layer "F.Cu")
		(net "M_C_CPU1_SB_DQ<29>")
	)
	(segment
		(start 29.13253 -196.466714)
		(end 30.771846 -196.466714)
		(width 0.20066)
		(layer "F.Cu")
		(net "M_C_CPU1_SB_DQ<29>")
	)
	(segment
		(start 23.228046 -196.466714)
		(end 24.562308 -196.466714)
		(width 0.20066)
		(layer "F.Cu")
		(net "M_C_CPU1_SB_DQ<29>")
	)
	(segment
		(start 24.562308 -196.466714)
		(end 24.773636 -196.678042)
		(width 0.20066)
		(layer "F.Cu")
		(net "M_C_CPU1_SB_DQ<29>")
	)
	(segment
		(start 28.529026 -196.041772)
		(end 28.707588 -196.041772)
		(width 0.20066)
		(layer "F.Cu")
		(net "M_C_CPU1_SB_DQ<29>")
	)
	(segment
		(start 97.073466 -227.367084)
		(end 97.073212 -227.36683)
		(width 0.20066)
		(layer "F.Cu")
		(net "M_C_CPU1_SB_DQ<29>")
	)
	(segment
		(start 25.432512 -196.52361)
		(end 25.432512 -196.195442)
		(width 0.20066)
		(layer "F.Cu")
		(net "M_C_CPU1_SB_DQ<29>")
	)
	(segment
		(start 31.876746 -196.466714)
		(end 30.771846 -196.466714)
		(width 0.20066)
		(layer "F.Cu")
		(net "M_C_CPU1_SB_DQ<29>")
	)
	(segment
		(start 26.20391 -196.032882)
		(end 26.2128 -196.041772)
		(width 0.1016)
		(layer "F.Cu")
		(net "M_C_CPU1_SB_DQ<29>")
	)
	(segment
		(start 24.773636 -196.678042)
		(end 25.27808 -196.678042)
		(width 0.20066)
		(layer "F.Cu")
		(net "M_C_CPU1_SB_DQ<29>")
	)
	(segment
		(start 28.707588 -196.041772)
		(end 29.13253 -196.466714)
		(width 0.20066)
		(layer "F.Cu")
		(net "M_C_CPU1_SB_DQ<29>")
	)
	(segment
		(start 25.27808 -196.678042)
		(end 25.432512 -196.52361)
		(width 0.20066)
		(layer "F.Cu")
		(net "M_C_CPU1_SB_DQ<29>")
	)
	(segment
		(start 26.2128 -196.041772)
		(end 28.198318 -196.041772)
		(width 0.1016)
		(layer "F.Cu")
		(net "M_C_CPU1_SB_DQ<29>")
	)
	(segment
		(start 25.595072 -196.032882)
		(end 26.20391 -196.032882)
		(width 0.20066)
		(layer "F.Cu")
		(net "M_C_CPU1_SB_DQ<29>")
	)
	(segment
		(start 97.073212 -227.36683)
		(end 97.073212 -226.831144)
		(width 0.20066)
		(layer "F.Cu")
		(net "M_C_CPU1_SB_DQ<29>")
	)
	(segment
		(start 86.078568 -223.085914)
		(end 86.068154 -223.079818)
		(width 0.088646)
		(layer "In6.Cu")
		(net "M_C_CPU1_SB_DQ<29>")
	)
	(segment
		(start 95.289116 -226.017328)
		(end 95.289116 -226.003104)
		(width 0.088646)
		(layer "In6.Cu")
		(net "M_C_CPU1_SB_DQ<29>")
	)
	(segment
		(start 83.428332 -219.712286)
		(end 83.094068 -219.378022)
		(width 0.18288)
		(layer "In6.Cu")
		(net "M_C_CPU1_SB_DQ<29>")
	)
	(segment
		(start 89.837768 -224.7138)
		(end 89.828878 -224.70872)
		(width 0.088646)
		(layer "In6.Cu")
		(net "M_C_CPU1_SB_DQ<29>")
	)
	(segment
		(start 92.100654 -224.70872)
		(end 92.091764 -224.7138)
		(width 0.088646)
		(layer "In6.Cu")
		(net "M_C_CPU1_SB_DQ<29>")
	)
	(segment
		(start 91.529916 -224.389442)
		(end 91.529916 -224.379536)
		(width 0.088646)
		(layer "In6.Cu")
		(net "M_C_CPU1_SB_DQ<29>")
	)
	(segment
		(start 84.951062 -221.235016)
		(end 83.428332 -219.712286)
		(width 0.088646)
		(layer "In6.Cu")
		(net "M_C_CPU1_SB_DQ<29>")
	)
	(segment
		(start 90.399616 -224.373948)
		(end 90.399616 -224.389442)
		(width 0.088646)
		(layer "In6.Cu")
		(net "M_C_CPU1_SB_DQ<29>")
	)
	(segment
		(start 60.43549 -193.950336)
		(end 59.963304 -193.78549)
		(width 0.18288)
		(layer "In6.Cu")
		(net "M_C_CPU1_SB_DQ<29>")
	)
	(segment
		(start 39.971726 -193.13271)
		(end 39.435786 -193.202306)
		(width 0.18288)
		(layer "In6.Cu")
		(net "M_C_CPU1_SB_DQ<29>")
	)
	(segment
		(start 92.279216 -224.373948)
		(end 92.279216 -224.389442)
		(width 0.088646)
		(layer "In6.Cu")
		(net "M_C_CPU1_SB_DQ<29>")
	)
	(segment
		(start 93.409516 -224.389442)
		(end 93.409516 -224.379536)
		(width 0.088646)
		(layer "In6.Cu")
		(net "M_C_CPU1_SB_DQ<29>")
	)
	(segment
		(start 88.347296 -223.077278)
		(end 88.332564 -223.085914)
		(width 0.088646)
		(layer "In6.Cu")
		(net "M_C_CPU1_SB_DQ<29>")
	)
	(segment
		(start 37.818822 -193.50355)
		(end 36.250372 -193.972688)
		(width 0.18288)
		(layer "In6.Cu")
		(net "M_C_CPU1_SB_DQ<29>")
	)
	(segment
		(start 66.077084 -198.716392)
		(end 64.444118 -197.083426)
		(width 0.18288)
		(layer "In6.Cu")
		(net "M_C_CPU1_SB_DQ<29>")
	)
	(segment
		(start 89.180416 -223.575626)
		(end 89.180416 -223.561402)
		(width 0.088646)
		(layer "In6.Cu")
		(net "M_C_CPU1_SB_DQ<29>")
	)
	(segment
		(start 74.213974 -209.969354)
		(end 71.311008 -202.961748)
		(width 0.18288)
		(layer "In6.Cu")
		(net "M_C_CPU1_SB_DQ<29>")
	)
	(segment
		(start 88.332564 -223.085914)
		(end 88.324182 -223.09074)
		(width 0.088646)
		(layer "In6.Cu")
		(net "M_C_CPU1_SB_DQ<29>")
	)
	(segment
		(start 94.066614 -225.527616)
		(end 94.057724 -225.522536)
		(width 0.088646)
		(layer "In6.Cu")
		(net "M_C_CPU1_SB_DQ<29>")
	)
	(segment
		(start 67.065652 -198.716392)
		(end 66.077084 -198.716392)
		(width 0.18288)
		(layer "In6.Cu")
		(net "M_C_CPU1_SB_DQ<29>")
	)
	(segment
		(start 83.094068 -218.849448)
		(end 74.213974 -209.969354)
		(width 0.18288)
		(layer "In6.Cu")
		(net "M_C_CPU1_SB_DQ<29>")
	)
	(segment
		(start 83.094068 -219.378022)
		(end 83.094068 -218.849448)
		(width 0.18288)
		(layer "In6.Cu")
		(net "M_C_CPU1_SB_DQ<29>")
	)
	(segment
		(start 93.596968 -224.7138)
		(end 93.588078 -224.70872)
		(width 0.088646)
		(layer "In6.Cu")
		(net "M_C_CPU1_SB_DQ<29>")
	)
	(segment
		(start 95.006414 -225.527616)
		(end 94.991682 -225.51898)
		(width 0.088646)
		(layer "In6.Cu")
		(net "M_C_CPU1_SB_DQ<29>")
	)
	(segment
		(start 61.409326 -194.924172)
		(end 60.43549 -193.950336)
		(width 0.18288)
		(layer "In6.Cu")
		(net "M_C_CPU1_SB_DQ<29>")
	)
	(segment
		(start 58.362342 -193.494152)
		(end 53.664612 -193.13271)
		(width 0.18288)
		(layer "In6.Cu")
		(net "M_C_CPU1_SB_DQ<29>")
	)
	(segment
		(start 36.250372 -193.972688)
		(end 35.45078 -194.32778)
		(width 0.18288)
		(layer "In6.Cu")
		(net "M_C_CPU1_SB_DQ<29>")
	)
	(segment
		(start 89.650316 -224.389442)
		(end 89.650316 -224.379536)
		(width 0.088646)
		(layer "In6.Cu")
		(net "M_C_CPU1_SB_DQ<29>")
	)
	(segment
		(start 95.476568 -226.341686)
		(end 95.467678 -226.336606)
		(width 0.088646)
		(layer "In6.Cu")
		(net "M_C_CPU1_SB_DQ<29>")
	)
	(segment
		(start 59.963304 -193.78549)
		(end 58.362342 -193.494152)
		(width 0.18288)
		(layer "In6.Cu")
		(net "M_C_CPU1_SB_DQ<29>")
	)
	(segment
		(start 53.664612 -193.13271)
		(end 39.971726 -193.13271)
		(width 0.18288)
		(layer "In6.Cu")
		(net "M_C_CPU1_SB_DQ<29>")
	)
	(segment
		(start 71.311008 -202.961748)
		(end 67.065652 -198.716392)
		(width 0.18288)
		(layer "In6.Cu")
		(net "M_C_CPU1_SB_DQ<29>")
	)
	(segment
		(start 61.409326 -195.686426)
		(end 61.409326 -194.924172)
		(width 0.18288)
		(layer "In6.Cu")
		(net "M_C_CPU1_SB_DQ<29>")
	)
	(segment
		(start 63.568326 -197.083426)
		(end 62.679326 -196.194426)
		(width 0.18288)
		(layer "In6.Cu")
		(net "M_C_CPU1_SB_DQ<29>")
	)
	(segment
		(start 35.45078 -194.32778)
		(end 31.876746 -196.466714)
		(width 0.18288)
		(layer "In6.Cu")
		(net "M_C_CPU1_SB_DQ<29>")
	)
	(segment
		(start 64.444118 -197.083426)
		(end 63.568326 -197.083426)
		(width 0.18288)
		(layer "In6.Cu")
		(net "M_C_CPU1_SB_DQ<29>")
	)
	(segment
		(start 96.493584 -226.386136)
		(end 96.416368 -226.341686)
		(width 0.088646)
		(layer "In6.Cu")
		(net "M_C_CPU1_SB_DQ<29>")
	)
	(segment
		(start 91.717368 -224.7138)
		(end 91.708478 -224.70872)
		(width 0.088646)
		(layer "In6.Cu")
		(net "M_C_CPU1_SB_DQ<29>")
	)
	(segment
		(start 84.951062 -222.761556)
		(end 84.951062 -221.235016)
		(width 0.088646)
		(layer "In6.Cu")
		(net "M_C_CPU1_SB_DQ<29>")
	)
	(segment
		(start 90.221054 -224.70872)
		(end 90.212164 -224.7138)
		(width 0.088646)
		(layer "In6.Cu")
		(net "M_C_CPU1_SB_DQ<29>")
	)
	(segment
		(start 91.247468 -223.899984)
		(end 91.237054 -223.893888)
		(width 0.088646)
		(layer "In6.Cu")
		(net "M_C_CPU1_SB_DQ<29>")
	)
	(segment
		(start 89.367868 -223.899984)
		(end 89.358978 -223.894904)
		(width 0.088646)
		(layer "In6.Cu")
		(net "M_C_CPU1_SB_DQ<29>")
	)
	(segment
		(start 93.879162 -225.203258)
		(end 93.879162 -225.187764)
		(width 0.088646)
		(layer "In6.Cu")
		(net "M_C_CPU1_SB_DQ<29>")
	)
	(segment
		(start 39.435786 -193.202306)
		(end 37.818822 -193.50355)
		(width 0.18288)
		(layer "In6.Cu")
		(net "M_C_CPU1_SB_DQ<29>")
	)
	(segment
		(start 61.917326 -196.194426)
		(end 61.409326 -195.686426)
		(width 0.18288)
		(layer "In6.Cu")
		(net "M_C_CPU1_SB_DQ<29>")
	)
	(segment
		(start 62.679326 -196.194426)
		(end 61.917326 -196.194426)
		(width 0.18288)
		(layer "In6.Cu")
		(net "M_C_CPU1_SB_DQ<29>")
	)
	(segment
		(start 93.127068 -223.899984)
		(end 93.116654 -223.893888)
		(width 0.088646)
		(layer "In6.Cu")
		(net "M_C_CPU1_SB_DQ<29>")
	)
	(segment
		(start 87.403178 -223.079818)
		(end 87.392764 -223.085914)
		(width 0.088646)
		(layer "In6.Cu")
		(net "M_C_CPU1_SB_DQ<29>")
	)
	(arc
		(start 89.650316 -224.379536)
		(mid 89.572205 -224.102587)
		(end 89.367868 -223.899984)
		(width 0.088646)
		(layer "In6.Cu")
		(net "M_C_CPU1_SB_DQ<29>")
	)
	(arc
		(start 86.452964 -223.085914)
		(mid 86.265766 -223.136057)
		(end 86.078568 -223.085914)
		(width 0.088646)
		(layer "In6.Cu")
		(net "M_C_CPU1_SB_DQ<29>")
	)
	(arc
		(start 87.958422 -223.085914)
		(mid 87.681609 -223.010078)
		(end 87.403178 -223.079818)
		(width 0.088646)
		(layer "In6.Cu")
		(net "M_C_CPU1_SB_DQ<29>")
	)
	(arc
		(start 90.399616 -224.389442)
		(mid 90.351937 -224.572342)
		(end 90.221054 -224.70872)
		(width 0.088646)
		(layer "In6.Cu")
		(net "M_C_CPU1_SB_DQ<29>")
	)
	(arc
		(start 93.116654 -223.893888)
		(mid 92.838222 -223.824042)
		(end 92.56141 -223.899984)
		(width 0.088646)
		(layer "In6.Cu")
		(net "M_C_CPU1_SB_DQ<29>")
	)
	(arc
		(start 94.057724 -225.522536)
		(mid 93.92681 -225.386176)
		(end 93.879162 -225.203258)
		(width 0.088646)
		(layer "In6.Cu")
		(net "M_C_CPU1_SB_DQ<29>")
	)
	(arc
		(start 89.358978 -223.894904)
		(mid 89.228064 -223.758544)
		(end 89.180416 -223.575626)
		(width 0.088646)
		(layer "In6.Cu")
		(net "M_C_CPU1_SB_DQ<29>")
	)
	(arc
		(start 90.212164 -224.7138)
		(mid 90.024966 -224.763943)
		(end 89.837768 -224.7138)
		(width 0.088646)
		(layer "In6.Cu")
		(net "M_C_CPU1_SB_DQ<29>")
	)
	(arc
		(start 89.180416 -223.561402)
		(mid 89.101275 -223.286779)
		(end 88.897968 -223.085914)
		(width 0.088646)
		(layer "In6.Cu")
		(net "M_C_CPU1_SB_DQ<29>")
	)
	(arc
		(start 95.289116 -226.003104)
		(mid 95.209897 -225.728419)
		(end 95.006414 -225.527616)
		(width 0.088646)
		(layer "In6.Cu")
		(net "M_C_CPU1_SB_DQ<29>")
	)
	(arc
		(start 86.068154 -223.079818)
		(mid 85.789722 -223.010004)
		(end 85.51291 -223.085914)
		(width 0.088646)
		(layer "In6.Cu")
		(net "M_C_CPU1_SB_DQ<29>")
	)
	(arc
		(start 88.897968 -223.085914)
		(mid 88.623739 -223.009989)
		(end 88.347296 -223.077278)
		(width 0.088646)
		(layer "In6.Cu")
		(net "M_C_CPU1_SB_DQ<29>")
	)
	(arc
		(start 94.991682 -225.51898)
		(mid 94.715241 -225.451814)
		(end 94.44101 -225.527616)
		(width 0.088646)
		(layer "In6.Cu")
		(net "M_C_CPU1_SB_DQ<29>")
	)
	(arc
		(start 87.018368 -223.085914)
		(mid 86.735666 -223.010172)
		(end 86.452964 -223.085914)
		(width 0.088646)
		(layer "In6.Cu")
		(net "M_C_CPU1_SB_DQ<29>")
	)
	(arc
		(start 93.409516 -224.379536)
		(mid 93.331405 -224.102587)
		(end 93.127068 -223.899984)
		(width 0.088646)
		(layer "In6.Cu")
		(net "M_C_CPU1_SB_DQ<29>")
	)
	(arc
		(start 90.68181 -223.899984)
		(mid 90.478987 -224.100215)
		(end 90.399616 -224.373948)
		(width 0.088646)
		(layer "In6.Cu")
		(net "M_C_CPU1_SB_DQ<29>")
	)
	(arc
		(start 94.44101 -225.527616)
		(mid 94.253812 -225.577759)
		(end 94.066614 -225.527616)
		(width 0.088646)
		(layer "In6.Cu")
		(net "M_C_CPU1_SB_DQ<29>")
	)
	(arc
		(start 95.467678 -226.336606)
		(mid 95.336764 -226.200246)
		(end 95.289116 -226.017328)
		(width 0.088646)
		(layer "In6.Cu")
		(net "M_C_CPU1_SB_DQ<29>")
	)
	(arc
		(start 92.56141 -223.899984)
		(mid 92.358587 -224.100215)
		(end 92.279216 -224.373948)
		(width 0.088646)
		(layer "In6.Cu")
		(net "M_C_CPU1_SB_DQ<29>")
	)
	(arc
		(start 91.529916 -224.379536)
		(mid 91.451805 -224.102587)
		(end 91.247468 -223.899984)
		(width 0.088646)
		(layer "In6.Cu")
		(net "M_C_CPU1_SB_DQ<29>")
	)
	(arc
		(start 88.324182 -223.09074)
		(mid 88.140674 -223.136018)
		(end 87.958422 -223.085914)
		(width 0.088646)
		(layer "In6.Cu")
		(net "M_C_CPU1_SB_DQ<29>")
	)
	(arc
		(start 87.392764 -223.085914)
		(mid 87.205566 -223.136057)
		(end 87.018368 -223.085914)
		(width 0.088646)
		(layer "In6.Cu")
		(net "M_C_CPU1_SB_DQ<29>")
	)
	(arc
		(start 93.588078 -224.70872)
		(mid 93.457164 -224.57236)
		(end 93.409516 -224.389442)
		(width 0.088646)
		(layer "In6.Cu")
		(net "M_C_CPU1_SB_DQ<29>")
	)
	(arc
		(start 91.237054 -223.893888)
		(mid 90.958622 -223.824042)
		(end 90.68181 -223.899984)
		(width 0.088646)
		(layer "In6.Cu")
		(net "M_C_CPU1_SB_DQ<29>")
	)
	(arc
		(start 97.073212 -226.831144)
		(mid 96.797976 -226.589651)
		(end 96.493584 -226.386136)
		(width 0.088646)
		(layer "In6.Cu")
		(net "M_C_CPU1_SB_DQ<29>")
	)
	(arc
		(start 92.091764 -224.7138)
		(mid 91.904566 -224.763943)
		(end 91.717368 -224.7138)
		(width 0.088646)
		(layer "In6.Cu")
		(net "M_C_CPU1_SB_DQ<29>")
	)
	(arc
		(start 89.828878 -224.70872)
		(mid 89.697964 -224.57236)
		(end 89.650316 -224.389442)
		(width 0.088646)
		(layer "In6.Cu")
		(net "M_C_CPU1_SB_DQ<29>")
	)
	(arc
		(start 95.850964 -226.341686)
		(mid 95.663766 -226.391829)
		(end 95.476568 -226.341686)
		(width 0.088646)
		(layer "In6.Cu")
		(net "M_C_CPU1_SB_DQ<29>")
	)
	(arc
		(start 93.879162 -225.187764)
		(mid 93.799792 -224.91403)
		(end 93.596968 -224.7138)
		(width 0.088646)
		(layer "In6.Cu")
		(net "M_C_CPU1_SB_DQ<29>")
	)
	(arc
		(start 91.708478 -224.70872)
		(mid 91.577564 -224.57236)
		(end 91.529916 -224.389442)
		(width 0.088646)
		(layer "In6.Cu")
		(net "M_C_CPU1_SB_DQ<29>")
	)
	(arc
		(start 92.279216 -224.389442)
		(mid 92.231537 -224.572342)
		(end 92.100654 -224.70872)
		(width 0.088646)
		(layer "In6.Cu")
		(net "M_C_CPU1_SB_DQ<29>")
	)
	(arc
		(start 85.51291 -223.085914)
		(mid 85.138435 -223.085868)
		(end 84.951062 -222.761556)
		(width 0.088646)
		(layer "In6.Cu")
		(net "M_C_CPU1_SB_DQ<29>")
	)
	(arc
		(start 96.416368 -226.341686)
		(mid 96.133666 -226.26591)
		(end 95.850964 -226.341686)
		(width 0.088646)
		(layer "In6.Cu")
		(net "M_C_CPU1_SB_DQ<29>")
	)
	(segment
		(start 25.432512 -198.232776)
		(end 25.432512 -197.943216)
		(width 0.20066)
		(layer "F.Cu")
		(net "M_C_CPU1_SB_DQ<28>")
	)
	(segment
		(start 24.801068 -198.405496)
		(end 25.259792 -198.405496)
		(width 0.20066)
		(layer "F.Cu")
		(net "M_C_CPU1_SB_DQ<28>")
	)
	(segment
		(start 31.876746 -198.166736)
		(end 30.771846 -198.166736)
		(width 0.20066)
		(layer "F.Cu")
		(net "M_C_CPU1_SB_DQ<28>")
	)
	(segment
		(start 28.529026 -197.741794)
		(end 28.977844 -197.741794)
		(width 0.20066)
		(layer "F.Cu")
		(net "M_C_CPU1_SB_DQ<28>")
	)
	(segment
		(start 25.259792 -198.405496)
		(end 25.432512 -198.232776)
		(width 0.20066)
		(layer "F.Cu")
		(net "M_C_CPU1_SB_DQ<28>")
	)
	(segment
		(start 26.20391 -197.733666)
		(end 26.212038 -197.741794)
		(width 0.101854)
		(layer "F.Cu")
		(net "M_C_CPU1_SB_DQ<28>")
	)
	(segment
		(start 24.562308 -198.166736)
		(end 24.801068 -198.405496)
		(width 0.20066)
		(layer "F.Cu")
		(net "M_C_CPU1_SB_DQ<28>")
	)
	(segment
		(start 28.977844 -197.741794)
		(end 29.402786 -198.166736)
		(width 0.20066)
		(layer "F.Cu")
		(net "M_C_CPU1_SB_DQ<28>")
	)
	(segment
		(start 25.642062 -197.733666)
		(end 26.20391 -197.733666)
		(width 0.20066)
		(layer "F.Cu")
		(net "M_C_CPU1_SB_DQ<28>")
	)
	(segment
		(start 94.254066 -227.367084)
		(end 94.253812 -227.36683)
		(width 0.20066)
		(layer "F.Cu")
		(net "M_C_CPU1_SB_DQ<28>")
	)
	(segment
		(start 25.432512 -197.943216)
		(end 25.642062 -197.733666)
		(width 0.20066)
		(layer "F.Cu")
		(net "M_C_CPU1_SB_DQ<28>")
	)
	(segment
		(start 94.253812 -227.36683)
		(end 94.253812 -226.831144)
		(width 0.20066)
		(layer "F.Cu")
		(net "M_C_CPU1_SB_DQ<28>")
	)
	(segment
		(start 29.402786 -198.166736)
		(end 30.771846 -198.166736)
		(width 0.20066)
		(layer "F.Cu")
		(net "M_C_CPU1_SB_DQ<28>")
	)
	(segment
		(start 23.228046 -198.166736)
		(end 24.562308 -198.166736)
		(width 0.20066)
		(layer "F.Cu")
		(net "M_C_CPU1_SB_DQ<28>")
	)
	(segment
		(start 26.459942 -197.741794)
		(end 28.529026 -197.741794)
		(width 0.1016)
		(layer "F.Cu")
		(net "M_C_CPU1_SB_DQ<28>")
	)
	(segment
		(start 26.212038 -197.741794)
		(end 26.459942 -197.741794)
		(width 0.101854)
		(layer "F.Cu")
		(net "M_C_CPU1_SB_DQ<28>")
	)
	(segment
		(start 42.57294 -196.224652)
		(end 42.57294 -196.716142)
		(width 0.18288)
		(layer "In6.Cu")
		(net "M_C_CPU1_SB_DQ<28>")
	)
	(segment
		(start 34.088578 -197.740778)
		(end 33.975294 -197.627494)
		(width 0.18288)
		(layer "In6.Cu")
		(net "M_C_CPU1_SB_DQ<28>")
	)
	(segment
		(start 39.543482 -196.702426)
		(end 37.225986 -196.702426)
		(width 0.18288)
		(layer "In6.Cu")
		(net "M_C_CPU1_SB_DQ<28>")
	)
	(segment
		(start 93.50121 -226.506786)
		(end 93.501464 -226.506786)
		(width 0.088646)
		(layer "In6.Cu")
		(net "M_C_CPU1_SB_DQ<28>")
	)
	(segment
		(start 53.12791 -195.193666)
		(end 46.446186 -195.193666)
		(width 0.18288)
		(layer "In6.Cu")
		(net "M_C_CPU1_SB_DQ<28>")
	)
	(segment
		(start 54.638702 -194.961002)
		(end 53.360574 -194.961002)
		(width 0.18288)
		(layer "In6.Cu")
		(net "M_C_CPU1_SB_DQ<28>")
	)
	(segment
		(start 66.433954 -200.260458)
		(end 65.396872 -200.260458)
		(width 0.18288)
		(layer "In6.Cu")
		(net "M_C_CPU1_SB_DQ<28>")
	)
	(segment
		(start 61.701426 -198.480426)
		(end 60.005976 -196.784976)
		(width 0.18288)
		(layer "In6.Cu")
		(net "M_C_CPU1_SB_DQ<28>")
	)
	(segment
		(start 37.225986 -196.702426)
		(end 36.187634 -197.740778)
		(width 0.18288)
		(layer "In6.Cu")
		(net "M_C_CPU1_SB_DQ<28>")
	)
	(segment
		(start 33.975294 -197.627494)
		(end 32.415988 -197.627494)
		(width 0.18288)
		(layer "In6.Cu")
		(net "M_C_CPU1_SB_DQ<28>")
	)
	(segment
		(start 58.818526 -195.985892)
		(end 55.663592 -195.985892)
		(width 0.18288)
		(layer "In6.Cu")
		(net "M_C_CPU1_SB_DQ<28>")
	)
	(segment
		(start 94.253812 -226.831144)
		(end 94.566486 -226.831144)
		(width 0.088646)
		(layer "In6.Cu")
		(net "M_C_CPU1_SB_DQ<28>")
	)
	(segment
		(start 41.87952 -196.224652)
		(end 41.69664 -196.041772)
		(width 0.18288)
		(layer "In6.Cu")
		(net "M_C_CPU1_SB_DQ<28>")
	)
	(segment
		(start 94.566486 -226.831144)
		(end 94.62389 -226.77374)
		(width 0.088646)
		(layer "In6.Cu")
		(net "M_C_CPU1_SB_DQ<28>")
	)
	(segment
		(start 36.187634 -197.740778)
		(end 34.088578 -197.740778)
		(width 0.18288)
		(layer "In6.Cu")
		(net "M_C_CPU1_SB_DQ<28>")
	)
	(segment
		(start 60.005976 -196.784976)
		(end 59.61761 -196.784976)
		(width 0.18288)
		(layer "In6.Cu")
		(net "M_C_CPU1_SB_DQ<28>")
	)
	(segment
		(start 88.989662 -225.217482)
		(end 88.989662 -225.194622)
		(width 0.088646)
		(layer "In6.Cu")
		(net "M_C_CPU1_SB_DQ<28>")
	)
	(segment
		(start 42.75582 -196.041772)
		(end 42.57294 -196.224652)
		(width 0.18288)
		(layer "In6.Cu")
		(net "M_C_CPU1_SB_DQ<28>")
	)
	(segment
		(start 84.456524 -223.975168)
		(end 83.82127 -223.339914)
		(width 0.088646)
		(layer "In6.Cu")
		(net "M_C_CPU1_SB_DQ<28>")
	)
	(segment
		(start 81.556606 -221.465648)
		(end 81.556606 -219.424504)
		(width 0.18288)
		(layer "In6.Cu")
		(net "M_C_CPU1_SB_DQ<28>")
	)
	(segment
		(start 42.57294 -196.716142)
		(end 42.39006 -196.899022)
		(width 0.18288)
		(layer "In6.Cu")
		(net "M_C_CPU1_SB_DQ<28>")
	)
	(segment
		(start 94.4499 -226.511866)
		(end 94.44101 -226.506786)
		(width 0.088646)
		(layer "In6.Cu")
		(net "M_C_CPU1_SB_DQ<28>")
	)
	(segment
		(start 45.59808 -196.041772)
		(end 42.75582 -196.041772)
		(width 0.18288)
		(layer "In6.Cu")
		(net "M_C_CPU1_SB_DQ<28>")
	)
	(segment
		(start 41.87952 -196.716142)
		(end 41.87952 -196.224652)
		(width 0.18288)
		(layer "In6.Cu")
		(net "M_C_CPU1_SB_DQ<28>")
	)
	(segment
		(start 91.162124 -225.699066)
		(end 91.15171 -225.69297)
		(width 0.088646)
		(layer "In6.Cu")
		(net "M_C_CPU1_SB_DQ<28>")
	)
	(segment
		(start 90.222578 -225.699066)
		(end 90.212164 -225.69297)
		(width 0.088646)
		(layer "In6.Cu")
		(net "M_C_CPU1_SB_DQ<28>")
	)
	(segment
		(start 46.446186 -195.193666)
		(end 45.59808 -196.041772)
		(width 0.18288)
		(layer "In6.Cu")
		(net "M_C_CPU1_SB_DQ<28>")
	)
	(segment
		(start 42.0624 -196.899022)
		(end 41.87952 -196.716142)
		(width 0.18288)
		(layer "In6.Cu")
		(net "M_C_CPU1_SB_DQ<28>")
	)
	(segment
		(start 93.219016 -226.027234)
		(end 93.219016 -226.017328)
		(width 0.088646)
		(layer "In6.Cu")
		(net "M_C_CPU1_SB_DQ<28>")
	)
	(segment
		(start 83.163918 -221.797118)
		(end 82.479642 -221.797118)
		(width 0.088646)
		(layer "In6.Cu")
		(net "M_C_CPU1_SB_DQ<28>")
	)
	(segment
		(start 83.82127 -223.339914)
		(end 83.82127 -222.45447)
		(width 0.088646)
		(layer "In6.Cu")
		(net "M_C_CPU1_SB_DQ<28>")
	)
	(segment
		(start 32.415988 -197.627494)
		(end 31.876746 -198.166736)
		(width 0.18288)
		(layer "In6.Cu")
		(net "M_C_CPU1_SB_DQ<28>")
	)
	(segment
		(start 84.584286 -224.07118)
		(end 84.573872 -224.065084)
		(width 0.088646)
		(layer "In6.Cu")
		(net "M_C_CPU1_SB_DQ<28>")
	)
	(segment
		(start 88.341454 -224.070164)
		(end 88.332564 -224.065084)
		(width 0.088646)
		(layer "In6.Cu")
		(net "M_C_CPU1_SB_DQ<28>")
	)
	(segment
		(start 82.479642 -221.797118)
		(end 81.888076 -221.797118)
		(width 0.18288)
		(layer "In6.Cu")
		(net "M_C_CPU1_SB_DQ<28>")
	)
	(segment
		(start 72.84339 -210.711288)
		(end 69.986144 -203.812648)
		(width 0.18288)
		(layer "In6.Cu")
		(net "M_C_CPU1_SB_DQ<28>")
	)
	(segment
		(start 81.888076 -221.797118)
		(end 81.556606 -221.465648)
		(width 0.18288)
		(layer "In6.Cu")
		(net "M_C_CPU1_SB_DQ<28>")
	)
	(segment
		(start 63.060326 -199.242426)
		(end 62.298326 -198.480426)
		(width 0.18288)
		(layer "In6.Cu")
		(net "M_C_CPU1_SB_DQ<28>")
	)
	(segment
		(start 65.396872 -200.260458)
		(end 64.37884 -199.242426)
		(width 0.18288)
		(layer "In6.Cu")
		(net "M_C_CPU1_SB_DQ<28>")
	)
	(segment
		(start 42.39006 -196.899022)
		(end 42.0624 -196.899022)
		(width 0.18288)
		(layer "In6.Cu")
		(net "M_C_CPU1_SB_DQ<28>")
	)
	(segment
		(start 41.69664 -196.041772)
		(end 40.204136 -196.041772)
		(width 0.18288)
		(layer "In6.Cu")
		(net "M_C_CPU1_SB_DQ<28>")
	)
	(segment
		(start 94.066614 -226.506786)
		(end 94.051882 -226.515422)
		(width 0.088646)
		(layer "In6.Cu")
		(net "M_C_CPU1_SB_DQ<28>")
	)
	(segment
		(start 40.204136 -196.041772)
		(end 39.543482 -196.702426)
		(width 0.18288)
		(layer "In6.Cu")
		(net "M_C_CPU1_SB_DQ<28>")
	)
	(segment
		(start 55.663592 -195.985892)
		(end 54.638702 -194.961002)
		(width 0.18288)
		(layer "In6.Cu")
		(net "M_C_CPU1_SB_DQ<28>")
	)
	(segment
		(start 92.106496 -225.701606)
		(end 92.091764 -225.69297)
		(width 0.088646)
		(layer "In6.Cu")
		(net "M_C_CPU1_SB_DQ<28>")
	)
	(segment
		(start 88.520016 -224.399348)
		(end 88.520016 -224.389442)
		(width 0.088646)
		(layer "In6.Cu")
		(net "M_C_CPU1_SB_DQ<28>")
	)
	(segment
		(start 53.360574 -194.961002)
		(end 53.12791 -195.193666)
		(width 0.18288)
		(layer "In6.Cu")
		(net "M_C_CPU1_SB_DQ<28>")
	)
	(segment
		(start 81.556606 -219.424504)
		(end 72.84339 -210.711288)
		(width 0.18288)
		(layer "In6.Cu")
		(net "M_C_CPU1_SB_DQ<28>")
	)
	(segment
		(start 89.287096 -225.701606)
		(end 89.272364 -225.69297)
		(width 0.088646)
		(layer "In6.Cu")
		(net "M_C_CPU1_SB_DQ<28>")
	)
	(segment
		(start 83.82127 -222.45447)
		(end 83.163918 -221.797118)
		(width 0.088646)
		(layer "In6.Cu")
		(net "M_C_CPU1_SB_DQ<28>")
	)
	(segment
		(start 62.298326 -198.480426)
		(end 61.701426 -198.480426)
		(width 0.18288)
		(layer "In6.Cu")
		(net "M_C_CPU1_SB_DQ<28>")
	)
	(segment
		(start 86.078568 -224.065084)
		(end 86.068154 -224.07118)
		(width 0.088646)
		(layer "In6.Cu")
		(net "M_C_CPU1_SB_DQ<28>")
	)
	(segment
		(start 64.37884 -199.242426)
		(end 63.060326 -199.242426)
		(width 0.18288)
		(layer "In6.Cu")
		(net "M_C_CPU1_SB_DQ<28>")
	)
	(segment
		(start 59.61761 -196.784976)
		(end 58.818526 -195.985892)
		(width 0.18288)
		(layer "In6.Cu")
		(net "M_C_CPU1_SB_DQ<28>")
	)
	(segment
		(start 93.040454 -225.69805)
		(end 93.031564 -225.69297)
		(width 0.088646)
		(layer "In6.Cu")
		(net "M_C_CPU1_SB_DQ<28>")
	)
	(segment
		(start 69.986144 -203.812648)
		(end 66.433954 -200.260458)
		(width 0.18288)
		(layer "In6.Cu")
		(net "M_C_CPU1_SB_DQ<28>")
	)
	(arc
		(start 88.332564 -224.065084)
		(mid 88.145366 -224.014941)
		(end 87.958168 -224.065084)
		(width 0.088646)
		(layer "In6.Cu")
		(net "M_C_CPU1_SB_DQ<28>")
	)
	(arc
		(start 90.212164 -225.69297)
		(mid 90.024966 -225.642827)
		(end 89.837768 -225.69297)
		(width 0.088646)
		(layer "In6.Cu")
		(net "M_C_CPU1_SB_DQ<28>")
	)
	(arc
		(start 87.392764 -224.065084)
		(mid 87.205566 -224.014941)
		(end 87.018368 -224.065084)
		(width 0.088646)
		(layer "In6.Cu")
		(net "M_C_CPU1_SB_DQ<28>")
	)
	(arc
		(start 86.452964 -224.065084)
		(mid 86.265766 -224.014941)
		(end 86.078568 -224.065084)
		(width 0.088646)
		(layer "In6.Cu")
		(net "M_C_CPU1_SB_DQ<28>")
	)
	(arc
		(start 89.272364 -225.69297)
		(mid 89.068883 -225.492166)
		(end 88.989662 -225.217482)
		(width 0.088646)
		(layer "In6.Cu")
		(net "M_C_CPU1_SB_DQ<28>")
	)
	(arc
		(start 94.62389 -226.77374)
		(mid 94.565734 -226.623627)
		(end 94.4499 -226.511866)
		(width 0.088646)
		(layer "In6.Cu")
		(net "M_C_CPU1_SB_DQ<28>")
	)
	(arc
		(start 88.989662 -225.194622)
		(mid 88.937392 -225.012257)
		(end 88.802464 -224.8789)
		(width 0.088646)
		(layer "In6.Cu")
		(net "M_C_CPU1_SB_DQ<28>")
	)
	(arc
		(start 94.44101 -226.506786)
		(mid 94.253812 -226.456643)
		(end 94.066614 -226.506786)
		(width 0.088646)
		(layer "In6.Cu")
		(net "M_C_CPU1_SB_DQ<28>")
	)
	(arc
		(start 87.018368 -224.065084)
		(mid 86.735666 -224.14086)
		(end 86.452964 -224.065084)
		(width 0.088646)
		(layer "In6.Cu")
		(net "M_C_CPU1_SB_DQ<28>")
	)
	(arc
		(start 85.138514 -224.065084)
		(mid 84.862209 -224.1407)
		(end 84.584286 -224.07118)
		(width 0.088646)
		(layer "In6.Cu")
		(net "M_C_CPU1_SB_DQ<28>")
	)
	(arc
		(start 92.091764 -225.69297)
		(mid 91.904566 -225.642827)
		(end 91.717368 -225.69297)
		(width 0.088646)
		(layer "In6.Cu")
		(net "M_C_CPU1_SB_DQ<28>")
	)
	(arc
		(start 93.219016 -226.017328)
		(mid 93.171337 -225.834428)
		(end 93.040454 -225.69805)
		(width 0.088646)
		(layer "In6.Cu")
		(net "M_C_CPU1_SB_DQ<28>")
	)
	(arc
		(start 92.657168 -225.69297)
		(mid 92.382939 -225.768895)
		(end 92.106496 -225.701606)
		(width 0.088646)
		(layer "In6.Cu")
		(net "M_C_CPU1_SB_DQ<28>")
	)
	(arc
		(start 90.777314 -225.69297)
		(mid 90.500755 -225.768679)
		(end 90.222578 -225.699066)
		(width 0.088646)
		(layer "In6.Cu")
		(net "M_C_CPU1_SB_DQ<28>")
	)
	(arc
		(start 88.802464 -224.8789)
		(mid 88.598129 -224.676295)
		(end 88.520016 -224.399348)
		(width 0.088646)
		(layer "In6.Cu")
		(net "M_C_CPU1_SB_DQ<28>")
	)
	(arc
		(start 84.573872 -224.065084)
		(mid 84.512245 -224.02398)
		(end 84.456524 -223.975168)
		(width 0.088646)
		(layer "In6.Cu")
		(net "M_C_CPU1_SB_DQ<28>")
	)
	(arc
		(start 86.068154 -224.07118)
		(mid 85.789722 -224.141026)
		(end 85.51291 -224.065084)
		(width 0.088646)
		(layer "In6.Cu")
		(net "M_C_CPU1_SB_DQ<28>")
	)
	(arc
		(start 87.958168 -224.065084)
		(mid 87.675466 -224.14086)
		(end 87.392764 -224.065084)
		(width 0.088646)
		(layer "In6.Cu")
		(net "M_C_CPU1_SB_DQ<28>")
	)
	(arc
		(start 94.051882 -226.515422)
		(mid 93.775407 -226.582742)
		(end 93.50121 -226.506786)
		(width 0.088646)
		(layer "In6.Cu")
		(net "M_C_CPU1_SB_DQ<28>")
	)
	(arc
		(start 93.031564 -225.69297)
		(mid 92.844366 -225.642827)
		(end 92.657168 -225.69297)
		(width 0.088646)
		(layer "In6.Cu")
		(net "M_C_CPU1_SB_DQ<28>")
	)
	(arc
		(start 93.501464 -226.506786)
		(mid 93.297129 -226.304181)
		(end 93.219016 -226.027234)
		(width 0.088646)
		(layer "In6.Cu")
		(net "M_C_CPU1_SB_DQ<28>")
	)
	(arc
		(start 85.51291 -224.065084)
		(mid 85.325712 -224.014941)
		(end 85.138514 -224.065084)
		(width 0.088646)
		(layer "In6.Cu")
		(net "M_C_CPU1_SB_DQ<28>")
	)
	(arc
		(start 89.837768 -225.69297)
		(mid 89.563539 -225.768895)
		(end 89.287096 -225.701606)
		(width 0.088646)
		(layer "In6.Cu")
		(net "M_C_CPU1_SB_DQ<28>")
	)
	(arc
		(start 91.15171 -225.69297)
		(mid 90.964512 -225.642827)
		(end 90.777314 -225.69297)
		(width 0.088646)
		(layer "In6.Cu")
		(net "M_C_CPU1_SB_DQ<28>")
	)
	(arc
		(start 91.717368 -225.69297)
		(mid 91.440555 -225.768806)
		(end 91.162124 -225.699066)
		(width 0.088646)
		(layer "In6.Cu")
		(net "M_C_CPU1_SB_DQ<28>")
	)
	(arc
		(start 88.520016 -224.389442)
		(mid 88.472337 -224.206542)
		(end 88.341454 -224.070164)
		(width 0.088646)
		(layer "In6.Cu")
		(net "M_C_CPU1_SB_DQ<28>")
	)
	(segment
		(start 97.073466 -228.99497)
		(end 97.073212 -228.994716)
		(width 0.20066)
		(layer "F.Cu")
		(net "M_C_CPU1_SB_DQ<27>")
	)
	(segment
		(start 32.51708 -201.991722)
		(end 32.666178 -201.842624)
		(width 0.20066)
		(layer "F.Cu")
		(net "M_C_CPU1_SB_DQ<27>")
	)
	(segment
		(start 97.073212 -228.994716)
		(end 97.073212 -228.45903)
		(width 0.20066)
		(layer "F.Cu")
		(net "M_C_CPU1_SB_DQ<27>")
	)
	(segment
		(start 29.899864 -201.991722)
		(end 31.972758 -201.991722)
		(width 0.1016)
		(layer "F.Cu")
		(net "M_C_CPU1_SB_DQ<27>")
	)
	(segment
		(start 32.794702 -201.562462)
		(end 33.189926 -201.562462)
		(width 0.20066)
		(layer "F.Cu")
		(net "M_C_CPU1_SB_DQ<27>")
	)
	(segment
		(start 33.189926 -201.562462)
		(end 33.401762 -201.774298)
		(width 0.20066)
		(layer "F.Cu")
		(net "M_C_CPU1_SB_DQ<27>")
	)
	(segment
		(start 33.401762 -201.774298)
		(end 33.848294 -201.774298)
		(width 0.20066)
		(layer "F.Cu")
		(net "M_C_CPU1_SB_DQ<27>")
	)
	(segment
		(start 27.328114 -201.56678)
		(end 29.025342 -201.56678)
		(width 0.20066)
		(layer "F.Cu")
		(net "M_C_CPU1_SB_DQ<27>")
	)
	(segment
		(start 29.151326 -201.863452)
		(end 29.29382 -202.005946)
		(width 0.20066)
		(layer "F.Cu")
		(net "M_C_CPU1_SB_DQ<27>")
	)
	(segment
		(start 29.151326 -201.692764)
		(end 29.151326 -201.863452)
		(width 0.20066)
		(layer "F.Cu")
		(net "M_C_CPU1_SB_DQ<27>")
	)
	(segment
		(start 29.647642 -202.005946)
		(end 29.661866 -201.991722)
		(width 0.101854)
		(layer "F.Cu")
		(net "M_C_CPU1_SB_DQ<27>")
	)
	(segment
		(start 32.666178 -201.690986)
		(end 32.794702 -201.562462)
		(width 0.20066)
		(layer "F.Cu")
		(net "M_C_CPU1_SB_DQ<27>")
	)
	(segment
		(start 29.29382 -202.005946)
		(end 29.647642 -202.005946)
		(width 0.20066)
		(layer "F.Cu")
		(net "M_C_CPU1_SB_DQ<27>")
	)
	(segment
		(start 32.666178 -201.842624)
		(end 32.666178 -201.690986)
		(width 0.20066)
		(layer "F.Cu")
		(net "M_C_CPU1_SB_DQ<27>")
	)
	(segment
		(start 34.055812 -201.56678)
		(end 34.871914 -201.56678)
		(width 0.20066)
		(layer "F.Cu")
		(net "M_C_CPU1_SB_DQ<27>")
	)
	(segment
		(start 31.972758 -201.991722)
		(end 32.51708 -201.991722)
		(width 0.20066)
		(layer "F.Cu")
		(net "M_C_CPU1_SB_DQ<27>")
	)
	(segment
		(start 35.976814 -201.56678)
		(end 34.871914 -201.56678)
		(width 0.20066)
		(layer "F.Cu")
		(net "M_C_CPU1_SB_DQ<27>")
	)
	(segment
		(start 29.661866 -201.991722)
		(end 29.899864 -201.991722)
		(width 0.101854)
		(layer "F.Cu")
		(net "M_C_CPU1_SB_DQ<27>")
	)
	(segment
		(start 29.025342 -201.56678)
		(end 29.151326 -201.692764)
		(width 0.20066)
		(layer "F.Cu")
		(net "M_C_CPU1_SB_DQ<27>")
	)
	(segment
		(start 33.848294 -201.774298)
		(end 34.055812 -201.56678)
		(width 0.20066)
		(layer "F.Cu")
		(net "M_C_CPU1_SB_DQ<27>")
	)
	(segment
		(start 51.968654 -199.836278)
		(end 51.968654 -200.10882)
		(width 0.18288)
		(layer "In6.Cu")
		(net "M_C_CPU1_SB_DQ<27>")
	)
	(segment
		(start 64.457326 -203.090526)
		(end 63.517526 -203.090526)
		(width 0.18288)
		(layer "In6.Cu")
		(net "M_C_CPU1_SB_DQ<27>")
	)
	(segment
		(start 59.072526 -201.185526)
		(end 58.049414 -201.185526)
		(width 0.18288)
		(layer "In6.Cu")
		(net "M_C_CPU1_SB_DQ<27>")
	)
	(segment
		(start 43.67403 -200.073006)
		(end 43.51401 -200.233026)
		(width 0.18288)
		(layer "In6.Cu")
		(net "M_C_CPU1_SB_DQ<27>")
	)
	(segment
		(start 44.36745 -199.849232)
		(end 44.20743 -199.689212)
		(width 0.18288)
		(layer "In6.Cu")
		(net "M_C_CPU1_SB_DQ<27>")
	)
	(segment
		(start 68.843652 -206.952088)
		(end 66.563748 -204.672184)
		(width 0.18288)
		(layer "In6.Cu")
		(net "M_C_CPU1_SB_DQ<27>")
	)
	(segment
		(start 50.025554 -199.35571)
		(end 49.697894 -199.35571)
		(width 0.18288)
		(layer "In6.Cu")
		(net "M_C_CPU1_SB_DQ<27>")
	)
	(segment
		(start 66.563748 -204.672184)
		(end 66.038984 -204.672184)
		(width 0.18288)
		(layer "In6.Cu")
		(net "M_C_CPU1_SB_DQ<27>")
	)
	(segment
		(start 79.401162 -220.293184)
		(end 70.812152 -211.704174)
		(width 0.18288)
		(layer "In6.Cu")
		(net "M_C_CPU1_SB_DQ<27>")
	)
	(segment
		(start 59.298078 -200.959974)
		(end 59.072526 -201.185526)
		(width 0.18288)
		(layer "In6.Cu")
		(net "M_C_CPU1_SB_DQ<27>")
	)
	(segment
		(start 52.151534 -199.653398)
		(end 51.968654 -199.836278)
		(width 0.18288)
		(layer "In6.Cu")
		(net "M_C_CPU1_SB_DQ<27>")
	)
	(segment
		(start 89.287096 -227.960682)
		(end 89.272364 -227.969318)
		(width 0.088646)
		(layer "In6.Cu")
		(net "M_C_CPU1_SB_DQ<27>")
	)
	(segment
		(start 80.132174 -223.917764)
		(end 79.401162 -223.186752)
		(width 0.18288)
		(layer "In6.Cu")
		(net "M_C_CPU1_SB_DQ<27>")
	)
	(segment
		(start 45.75429 -199.849232)
		(end 45.59427 -199.689212)
		(width 0.18288)
		(layer "In6.Cu")
		(net "M_C_CPU1_SB_DQ<27>")
	)
	(segment
		(start 57.683654 -200.34504)
		(end 57.358534 -200.34504)
		(width 0.18288)
		(layer "In6.Cu")
		(net "M_C_CPU1_SB_DQ<27>")
	)
	(segment
		(start 46.772322 -201.141838)
		(end 46.27118 -200.640696)
		(width 0.18288)
		(layer "In6.Cu")
		(net "M_C_CPU1_SB_DQ<27>")
	)
	(segment
		(start 46.11116 -200.233026)
		(end 45.91431 -200.233026)
		(width 0.18288)
		(layer "In6.Cu")
		(net "M_C_CPU1_SB_DQ<27>")
	)
	(segment
		(start 52.479194 -199.653398)
		(end 52.151534 -199.653398)
		(width 0.18288)
		(layer "In6.Cu")
		(net "M_C_CPU1_SB_DQ<27>")
	)
	(segment
		(start 86.078568 -226.341686)
		(end 86.068154 -226.33559)
		(width 0.088646)
		(layer "In6.Cu")
		(net "M_C_CPU1_SB_DQ<27>")
	)
	(segment
		(start 50.391314 -200.2917)
		(end 50.208434 -200.10882)
		(width 0.18288)
		(layer "In6.Cu")
		(net "M_C_CPU1_SB_DQ<27>")
	)
	(segment
		(start 82.869786 -224.069656)
		(end 82.717894 -223.917764)
		(width 0.088646)
		(layer "In6.Cu")
		(net "M_C_CPU1_SB_DQ<27>")
	)
	(segment
		(start 36.56838 -201.56678)
		(end 35.976814 -201.56678)
		(width 0.18288)
		(layer "In6.Cu")
		(net "M_C_CPU1_SB_DQ<27>")
	)
	(segment
		(start 56.992774 -201.185526)
		(end 55.948326 -201.185526)
		(width 0.18288)
		(layer "In6.Cu")
		(net "M_C_CPU1_SB_DQ<27>")
	)
	(segment
		(start 91.999816 -228.467666)
		(end 91.999816 -228.444806)
		(width 0.088646)
		(layer "In6.Cu")
		(net "M_C_CPU1_SB_DQ<27>")
	)
	(segment
		(start 63.517526 -203.090526)
		(end 62.692026 -202.265026)
		(width 0.18288)
		(layer "In6.Cu")
		(net "M_C_CPU1_SB_DQ<27>")
	)
	(segment
		(start 95.381064 -228.134926)
		(end 95.38081 -228.134672)
		(width 0.088646)
		(layer "In6.Cu")
		(net "M_C_CPU1_SB_DQ<27>")
	)
	(segment
		(start 60.412122 -200.959974)
		(end 59.298078 -200.959974)
		(width 0.18288)
		(layer "In6.Cu")
		(net "M_C_CPU1_SB_DQ<27>")
	)
	(segment
		(start 62.692026 -202.265026)
		(end 61.717174 -202.265026)
		(width 0.18288)
		(layer "In6.Cu")
		(net "M_C_CPU1_SB_DQ<27>")
	)
	(segment
		(start 51.968654 -200.10882)
		(end 51.785774 -200.2917)
		(width 0.18288)
		(layer "In6.Cu")
		(net "M_C_CPU1_SB_DQ<27>")
	)
	(segment
		(start 44.20743 -199.689212)
		(end 43.83405 -199.689212)
		(width 0.18288)
		(layer "In6.Cu")
		(net "M_C_CPU1_SB_DQ<27>")
	)
	(segment
		(start 61.717174 -202.265026)
		(end 60.412122 -200.959974)
		(width 0.18288)
		(layer "In6.Cu")
		(net "M_C_CPU1_SB_DQ<27>")
	)
	(segment
		(start 47.306992 -201.141838)
		(end 46.772322 -201.141838)
		(width 0.18288)
		(layer "In6.Cu")
		(net "M_C_CPU1_SB_DQ<27>")
	)
	(segment
		(start 45.06087 -200.073006)
		(end 44.90085 -200.233026)
		(width 0.18288)
		(layer "In6.Cu")
		(net "M_C_CPU1_SB_DQ<27>")
	)
	(segment
		(start 82.869786 -224.288858)
		(end 82.869786 -224.069656)
		(width 0.088646)
		(layer "In6.Cu")
		(net "M_C_CPU1_SB_DQ<27>")
	)
	(segment
		(start 57.866534 -200.52792)
		(end 57.683654 -200.34504)
		(width 0.18288)
		(layer "In6.Cu")
		(net "M_C_CPU1_SB_DQ<27>")
	)
	(segment
		(start 43.51401 -200.233026)
		(end 37.902134 -200.233026)
		(width 0.18288)
		(layer "In6.Cu")
		(net "M_C_CPU1_SB_DQ<27>")
	)
	(segment
		(start 96.349312 -228.766878)
		(end 96.320864 -228.783388)
		(width 0.088646)
		(layer "In6.Cu")
		(net "M_C_CPU1_SB_DQ<27>")
	)
	(segment
		(start 52.662074 -200.10882)
		(end 52.662074 -199.836278)
		(width 0.18288)
		(layer "In6.Cu")
		(net "M_C_CPU1_SB_DQ<27>")
	)
	(segment
		(start 91.717114 -227.969318)
		(end 91.7067 -227.963222)
		(width 0.088646)
		(layer "In6.Cu")
		(net "M_C_CPU1_SB_DQ<27>")
	)
	(segment
		(start 94.066614 -228.783388)
		(end 94.051882 -228.774752)
		(width 0.088646)
		(layer "In6.Cu")
		(net "M_C_CPU1_SB_DQ<27>")
	)
	(segment
		(start 97.073212 -228.45903)
		(end 96.349312 -228.766878)
		(width 0.088646)
		(layer "In6.Cu")
		(net "M_C_CPU1_SB_DQ<27>")
	)
	(segment
		(start 84.855812 -226.265994)
		(end 84.575904 -226.265994)
		(width 0.088646)
		(layer "In6.Cu")
		(net "M_C_CPU1_SB_DQ<27>")
	)
	(segment
		(start 49.515014 -200.10882)
		(end 49.332134 -200.2917)
		(width 0.18288)
		(layer "In6.Cu")
		(net "M_C_CPU1_SB_DQ<27>")
	)
	(segment
		(start 82.717894 -223.917764)
		(end 82.479642 -223.917764)
		(width 0.088646)
		(layer "In6.Cu")
		(net "M_C_CPU1_SB_DQ<27>")
	)
	(segment
		(start 44.36745 -200.073006)
		(end 44.36745 -199.849232)
		(width 0.18288)
		(layer "In6.Cu")
		(net "M_C_CPU1_SB_DQ<27>")
	)
	(segment
		(start 51.785774 -200.2917)
		(end 50.391314 -200.2917)
		(width 0.18288)
		(layer "In6.Cu")
		(net "M_C_CPU1_SB_DQ<27>")
	)
	(segment
		(start 84.315046 -225.734118)
		(end 82.869786 -224.288858)
		(width 0.088646)
		(layer "In6.Cu")
		(net "M_C_CPU1_SB_DQ<27>")
	)
	(segment
		(start 79.401162 -223.186752)
		(end 79.401162 -220.293184)
		(width 0.18288)
		(layer "In6.Cu")
		(net "M_C_CPU1_SB_DQ<27>")
	)
	(segment
		(start 94.441264 -228.783134)
		(end 94.44101 -228.783388)
		(width 0.088646)
		(layer "In6.Cu")
		(net "M_C_CPU1_SB_DQ<27>")
	)
	(segment
		(start 66.038984 -204.672184)
		(end 64.457326 -203.090526)
		(width 0.18288)
		(layer "In6.Cu")
		(net "M_C_CPU1_SB_DQ<27>")
	)
	(segment
		(start 45.91431 -200.233026)
		(end 45.75429 -200.073006)
		(width 0.18288)
		(layer "In6.Cu")
		(net "M_C_CPU1_SB_DQ<27>")
	)
	(segment
		(start 45.06087 -199.849232)
		(end 45.06087 -200.073006)
		(width 0.18288)
		(layer "In6.Cu")
		(net "M_C_CPU1_SB_DQ<27>")
	)
	(segment
		(start 50.208434 -199.53859)
		(end 50.025554 -199.35571)
		(width 0.18288)
		(layer "In6.Cu")
		(net "M_C_CPU1_SB_DQ<27>")
	)
	(segment
		(start 49.332134 -200.2917)
		(end 48.15713 -200.2917)
		(width 0.18288)
		(layer "In6.Cu")
		(net "M_C_CPU1_SB_DQ<27>")
	)
	(segment
		(start 84.575904 -226.265994)
		(end 84.315046 -226.005136)
		(width 0.088646)
		(layer "In6.Cu")
		(net "M_C_CPU1_SB_DQ<27>")
	)
	(segment
		(start 44.90085 -200.233026)
		(end 44.52747 -200.233026)
		(width 0.18288)
		(layer "In6.Cu")
		(net "M_C_CPU1_SB_DQ<27>")
	)
	(segment
		(start 43.67403 -199.849232)
		(end 43.67403 -200.073006)
		(width 0.18288)
		(layer "In6.Cu")
		(net "M_C_CPU1_SB_DQ<27>")
	)
	(segment
		(start 95.946468 -228.783388)
		(end 95.66021 -228.618034)
		(width 0.088646)
		(layer "In6.Cu")
		(net "M_C_CPU1_SB_DQ<27>")
	)
	(segment
		(start 87.494364 -227.159058)
		(end 87.488268 -227.155502)
		(width 0.088646)
		(layer "In6.Cu")
		(net "M_C_CPU1_SB_DQ<27>")
	)
	(segment
		(start 55.0545 -200.2917)
		(end 52.844954 -200.2917)
		(width 0.18288)
		(layer "In6.Cu")
		(net "M_C_CPU1_SB_DQ<27>")
	)
	(segment
		(start 52.662074 -199.836278)
		(end 52.479194 -199.653398)
		(width 0.18288)
		(layer "In6.Cu")
		(net "M_C_CPU1_SB_DQ<27>")
	)
	(segment
		(start 84.315046 -226.005136)
		(end 84.315046 -225.734118)
		(width 0.088646)
		(layer "In6.Cu")
		(net "M_C_CPU1_SB_DQ<27>")
	)
	(segment
		(start 45.75429 -200.073006)
		(end 45.75429 -199.849232)
		(width 0.18288)
		(layer "In6.Cu")
		(net "M_C_CPU1_SB_DQ<27>")
	)
	(segment
		(start 46.27118 -200.393046)
		(end 46.11116 -200.233026)
		(width 0.18288)
		(layer "In6.Cu")
		(net "M_C_CPU1_SB_DQ<27>")
	)
	(segment
		(start 86.463378 -226.33559)
		(end 86.452964 -226.341686)
		(width 0.088646)
		(layer "In6.Cu")
		(net "M_C_CPU1_SB_DQ<27>")
	)
	(segment
		(start 93.126814 -228.783388)
		(end 93.112082 -228.774752)
		(width 0.088646)
		(layer "In6.Cu")
		(net "M_C_CPU1_SB_DQ<27>")
	)
	(segment
		(start 46.27118 -200.640696)
		(end 46.27118 -200.393046)
		(width 0.18288)
		(layer "In6.Cu")
		(net "M_C_CPU1_SB_DQ<27>")
	)
	(segment
		(start 58.049414 -201.185526)
		(end 57.866534 -201.002646)
		(width 0.18288)
		(layer "In6.Cu")
		(net "M_C_CPU1_SB_DQ<27>")
	)
	(segment
		(start 45.59427 -199.689212)
		(end 45.22089 -199.689212)
		(width 0.18288)
		(layer "In6.Cu")
		(net "M_C_CPU1_SB_DQ<27>")
	)
	(segment
		(start 88.347296 -227.960682)
		(end 88.332564 -227.969318)
		(width 0.088646)
		(layer "In6.Cu")
		(net "M_C_CPU1_SB_DQ<27>")
	)
	(segment
		(start 48.15713 -200.2917)
		(end 47.306992 -201.141838)
		(width 0.18288)
		(layer "In6.Cu")
		(net "M_C_CPU1_SB_DQ<27>")
	)
	(segment
		(start 55.948326 -201.185526)
		(end 55.0545 -200.2917)
		(width 0.18288)
		(layer "In6.Cu")
		(net "M_C_CPU1_SB_DQ<27>")
	)
	(segment
		(start 52.844954 -200.2917)
		(end 52.662074 -200.10882)
		(width 0.18288)
		(layer "In6.Cu")
		(net "M_C_CPU1_SB_DQ<27>")
	)
	(segment
		(start 70.812152 -211.704174)
		(end 68.843652 -206.952088)
		(width 0.18288)
		(layer "In6.Cu")
		(net "M_C_CPU1_SB_DQ<27>")
	)
	(segment
		(start 57.175654 -201.002646)
		(end 56.992774 -201.185526)
		(width 0.18288)
		(layer "In6.Cu")
		(net "M_C_CPU1_SB_DQ<27>")
	)
	(segment
		(start 57.175654 -200.52792)
		(end 57.175654 -201.002646)
		(width 0.18288)
		(layer "In6.Cu")
		(net "M_C_CPU1_SB_DQ<27>")
	)
	(segment
		(start 57.358534 -200.34504)
		(end 57.175654 -200.52792)
		(width 0.18288)
		(layer "In6.Cu")
		(net "M_C_CPU1_SB_DQ<27>")
	)
	(segment
		(start 87.030306 -226.348798)
		(end 87.018114 -226.341686)
		(width 0.088646)
		(layer "In6.Cu")
		(net "M_C_CPU1_SB_DQ<27>")
	)
	(segment
		(start 37.902134 -200.233026)
		(end 36.56838 -201.56678)
		(width 0.18288)
		(layer "In6.Cu")
		(net "M_C_CPU1_SB_DQ<27>")
	)
	(segment
		(start 87.488268 -227.155502)
		(end 87.479378 -227.150422)
		(width 0.088646)
		(layer "In6.Cu")
		(net "M_C_CPU1_SB_DQ<27>")
	)
	(segment
		(start 57.866534 -201.002646)
		(end 57.866534 -200.52792)
		(width 0.18288)
		(layer "In6.Cu")
		(net "M_C_CPU1_SB_DQ<27>")
	)
	(segment
		(start 95.006668 -228.134672)
		(end 95.006414 -228.134672)
		(width 0.088646)
		(layer "In6.Cu")
		(net "M_C_CPU1_SB_DQ<27>")
	)
	(segment
		(start 49.515014 -199.53859)
		(end 49.515014 -200.10882)
		(width 0.18288)
		(layer "In6.Cu")
		(net "M_C_CPU1_SB_DQ<27>")
	)
	(segment
		(start 49.697894 -199.35571)
		(end 49.515014 -199.53859)
		(width 0.18288)
		(layer "In6.Cu")
		(net "M_C_CPU1_SB_DQ<27>")
	)
	(segment
		(start 44.52747 -200.233026)
		(end 44.36745 -200.073006)
		(width 0.18288)
		(layer "In6.Cu")
		(net "M_C_CPU1_SB_DQ<27>")
	)
	(segment
		(start 90.226896 -227.960682)
		(end 90.212164 -227.969318)
		(width 0.088646)
		(layer "In6.Cu")
		(net "M_C_CPU1_SB_DQ<27>")
	)
	(segment
		(start 45.22089 -199.689212)
		(end 45.06087 -199.849232)
		(width 0.18288)
		(layer "In6.Cu")
		(net "M_C_CPU1_SB_DQ<27>")
	)
	(segment
		(start 43.83405 -199.689212)
		(end 43.67403 -199.849232)
		(width 0.18288)
		(layer "In6.Cu")
		(net "M_C_CPU1_SB_DQ<27>")
	)
	(segment
		(start 82.479642 -223.917764)
		(end 80.132174 -223.917764)
		(width 0.18288)
		(layer "In6.Cu")
		(net "M_C_CPU1_SB_DQ<27>")
	)
	(segment
		(start 95.006414 -228.134672)
		(end 94.720664 -228.299772)
		(width 0.088646)
		(layer "In6.Cu")
		(net "M_C_CPU1_SB_DQ<27>")
	)
	(segment
		(start 87.958168 -227.969318)
		(end 87.949278 -227.964238)
		(width 0.088646)
		(layer "In6.Cu")
		(net "M_C_CPU1_SB_DQ<27>")
	)
	(segment
		(start 50.208434 -200.10882)
		(end 50.208434 -199.53859)
		(width 0.18288)
		(layer "In6.Cu")
		(net "M_C_CPU1_SB_DQ<27>")
	)
	(arc
		(start 92.56141 -228.783388)
		(mid 92.374212 -228.833531)
		(end 92.187014 -228.783388)
		(width 0.088646)
		(layer "In6.Cu")
		(net "M_C_CPU1_SB_DQ<27>")
	)
	(arc
		(start 95.568262 -228.45903)
		(mid 95.518098 -228.271892)
		(end 95.381064 -228.134926)
		(width 0.088646)
		(layer "In6.Cu")
		(net "M_C_CPU1_SB_DQ<27>")
	)
	(arc
		(start 95.66021 -228.618034)
		(mid 95.59288 -228.550876)
		(end 95.568262 -228.45903)
		(width 0.088646)
		(layer "In6.Cu")
		(net "M_C_CPU1_SB_DQ<27>")
	)
	(arc
		(start 87.479378 -227.150422)
		(mid 87.348464 -227.014062)
		(end 87.300816 -226.831144)
		(width 0.088646)
		(layer "In6.Cu")
		(net "M_C_CPU1_SB_DQ<27>")
	)
	(arc
		(start 91.999816 -228.444806)
		(mid 91.920597 -228.170121)
		(end 91.717114 -227.969318)
		(width 0.088646)
		(layer "In6.Cu")
		(net "M_C_CPU1_SB_DQ<27>")
	)
	(arc
		(start 94.720664 -228.299772)
		(mid 94.653169 -228.36703)
		(end 94.628462 -228.45903)
		(width 0.088646)
		(layer "In6.Cu")
		(net "M_C_CPU1_SB_DQ<27>")
	)
	(arc
		(start 87.770716 -227.64496)
		(mid 87.6968 -227.365458)
		(end 87.494364 -227.159058)
		(width 0.088646)
		(layer "In6.Cu")
		(net "M_C_CPU1_SB_DQ<27>")
	)
	(arc
		(start 87.300816 -226.831144)
		(mid 87.228581 -226.55462)
		(end 87.030306 -226.348798)
		(width 0.088646)
		(layer "In6.Cu")
		(net "M_C_CPU1_SB_DQ<27>")
	)
	(arc
		(start 89.837768 -227.969318)
		(mid 89.563539 -227.893393)
		(end 89.287096 -227.960682)
		(width 0.088646)
		(layer "In6.Cu")
		(net "M_C_CPU1_SB_DQ<27>")
	)
	(arc
		(start 94.051882 -228.774752)
		(mid 93.775407 -228.707432)
		(end 93.50121 -228.783388)
		(width 0.088646)
		(layer "In6.Cu")
		(net "M_C_CPU1_SB_DQ<27>")
	)
	(arc
		(start 87.949278 -227.964238)
		(mid 87.818364 -227.827878)
		(end 87.770716 -227.64496)
		(width 0.088646)
		(layer "In6.Cu")
		(net "M_C_CPU1_SB_DQ<27>")
	)
	(arc
		(start 86.452964 -226.341686)
		(mid 86.265766 -226.391829)
		(end 86.078568 -226.341686)
		(width 0.088646)
		(layer "In6.Cu")
		(net "M_C_CPU1_SB_DQ<27>")
	)
	(arc
		(start 86.068154 -226.33559)
		(mid 85.789722 -226.265744)
		(end 85.51291 -226.341686)
		(width 0.088646)
		(layer "In6.Cu")
		(net "M_C_CPU1_SB_DQ<27>")
	)
	(arc
		(start 93.50121 -228.783388)
		(mid 93.314012 -228.833531)
		(end 93.126814 -228.783388)
		(width 0.088646)
		(layer "In6.Cu")
		(net "M_C_CPU1_SB_DQ<27>")
	)
	(arc
		(start 94.44101 -228.783388)
		(mid 94.253812 -228.833531)
		(end 94.066614 -228.783388)
		(width 0.088646)
		(layer "In6.Cu")
		(net "M_C_CPU1_SB_DQ<27>")
	)
	(arc
		(start 94.628462 -228.45903)
		(mid 94.578298 -228.646168)
		(end 94.441264 -228.783134)
		(width 0.088646)
		(layer "In6.Cu")
		(net "M_C_CPU1_SB_DQ<27>")
	)
	(arc
		(start 91.7067 -227.963222)
		(mid 91.428522 -227.89353)
		(end 91.151964 -227.969318)
		(width 0.088646)
		(layer "In6.Cu")
		(net "M_C_CPU1_SB_DQ<27>")
	)
	(arc
		(start 96.320864 -228.783388)
		(mid 96.133666 -228.833565)
		(end 95.946468 -228.783388)
		(width 0.088646)
		(layer "In6.Cu")
		(net "M_C_CPU1_SB_DQ<27>")
	)
	(arc
		(start 89.272364 -227.969318)
		(mid 89.085166 -228.019461)
		(end 88.897968 -227.969318)
		(width 0.088646)
		(layer "In6.Cu")
		(net "M_C_CPU1_SB_DQ<27>")
	)
	(arc
		(start 88.897968 -227.969318)
		(mid 88.623739 -227.893393)
		(end 88.347296 -227.960682)
		(width 0.088646)
		(layer "In6.Cu")
		(net "M_C_CPU1_SB_DQ<27>")
	)
	(arc
		(start 92.187014 -228.783388)
		(mid 92.052081 -228.650034)
		(end 91.999816 -228.467666)
		(width 0.088646)
		(layer "In6.Cu")
		(net "M_C_CPU1_SB_DQ<27>")
	)
	(arc
		(start 91.151964 -227.969318)
		(mid 90.964766 -228.019461)
		(end 90.777568 -227.969318)
		(width 0.088646)
		(layer "In6.Cu")
		(net "M_C_CPU1_SB_DQ<27>")
	)
	(arc
		(start 85.51291 -226.341686)
		(mid 85.325712 -226.391829)
		(end 85.138514 -226.341686)
		(width 0.088646)
		(layer "In6.Cu")
		(net "M_C_CPU1_SB_DQ<27>")
	)
	(arc
		(start 85.138514 -226.341686)
		(mid 85.002145 -226.285244)
		(end 84.855812 -226.265994)
		(width 0.088646)
		(layer "In6.Cu")
		(net "M_C_CPU1_SB_DQ<27>")
	)
	(arc
		(start 88.332564 -227.969318)
		(mid 88.145366 -228.019461)
		(end 87.958168 -227.969318)
		(width 0.088646)
		(layer "In6.Cu")
		(net "M_C_CPU1_SB_DQ<27>")
	)
	(arc
		(start 87.018114 -226.341686)
		(mid 86.741555 -226.265943)
		(end 86.463378 -226.33559)
		(width 0.088646)
		(layer "In6.Cu")
		(net "M_C_CPU1_SB_DQ<27>")
	)
	(arc
		(start 95.38081 -228.134672)
		(mid 95.193756 -228.084622)
		(end 95.006668 -228.134672)
		(width 0.088646)
		(layer "In6.Cu")
		(net "M_C_CPU1_SB_DQ<27>")
	)
	(arc
		(start 93.112082 -228.774752)
		(mid 92.835607 -228.707432)
		(end 92.56141 -228.783388)
		(width 0.088646)
		(layer "In6.Cu")
		(net "M_C_CPU1_SB_DQ<27>")
	)
	(arc
		(start 90.212164 -227.969318)
		(mid 90.024966 -228.019461)
		(end 89.837768 -227.969318)
		(width 0.088646)
		(layer "In6.Cu")
		(net "M_C_CPU1_SB_DQ<27>")
	)
	(arc
		(start 90.777568 -227.969318)
		(mid 90.503339 -227.893393)
		(end 90.226896 -227.960682)
		(width 0.088646)
		(layer "In6.Cu")
		(net "M_C_CPU1_SB_DQ<27>")
	)
	(segment
		(start 33.345374 -203.478638)
		(end 33.55721 -203.266802)
		(width 0.20066)
		(layer "F.Cu")
		(net "M_C_CPU1_SB_DQ<26>")
	)
	(segment
		(start 29.912818 -202.84186)
		(end 31.972758 -202.84186)
		(width 0.1016)
		(layer "F.Cu")
		(net "M_C_CPU1_SB_DQ<26>")
	)
	(segment
		(start 32.916876 -203.478638)
		(end 33.345374 -203.478638)
		(width 0.20066)
		(layer "F.Cu")
		(net "M_C_CPU1_SB_DQ<26>")
	)
	(segment
		(start 96.603312 -229.808786)
		(end 96.603566 -229.808532)
		(width 0.20066)
		(layer "F.Cu")
		(net "M_C_CPU1_SB_DQ<26>")
	)
	(segment
		(start 29.657802 -202.84186)
		(end 29.912818 -202.84186)
		(width 0.101854)
		(layer "F.Cu")
		(net "M_C_CPU1_SB_DQ<26>")
	)
	(segment
		(start 32.74949 -202.985624)
		(end 32.74949 -203.311252)
		(width 0.20066)
		(layer "F.Cu")
		(net "M_C_CPU1_SB_DQ<26>")
	)
	(segment
		(start 28.91028 -202.8317)
		(end 29.647642 -202.8317)
		(width 0.20066)
		(layer "F.Cu")
		(net "M_C_CPU1_SB_DQ<26>")
	)
	(segment
		(start 29.647642 -202.8317)
		(end 29.657802 -202.84186)
		(width 0.101854)
		(layer "F.Cu")
		(net "M_C_CPU1_SB_DQ<26>")
	)
	(segment
		(start 96.603566 -229.808532)
		(end 96.603566 -229.272846)
		(width 0.20066)
		(layer "F.Cu")
		(net "M_C_CPU1_SB_DQ<26>")
	)
	(segment
		(start 33.55721 -203.266802)
		(end 34.871914 -203.266802)
		(width 0.20066)
		(layer "F.Cu")
		(net "M_C_CPU1_SB_DQ<26>")
	)
	(segment
		(start 35.976814 -203.266802)
		(end 34.871914 -203.266802)
		(width 0.20066)
		(layer "F.Cu")
		(net "M_C_CPU1_SB_DQ<26>")
	)
	(segment
		(start 32.74949 -203.311252)
		(end 32.916876 -203.478638)
		(width 0.20066)
		(layer "F.Cu")
		(net "M_C_CPU1_SB_DQ<26>")
	)
	(segment
		(start 31.972758 -202.84186)
		(end 32.605726 -202.84186)
		(width 0.20066)
		(layer "F.Cu")
		(net "M_C_CPU1_SB_DQ<26>")
	)
	(segment
		(start 28.475178 -203.266802)
		(end 28.91028 -202.8317)
		(width 0.20066)
		(layer "F.Cu")
		(net "M_C_CPU1_SB_DQ<26>")
	)
	(segment
		(start 32.605726 -202.84186)
		(end 32.74949 -202.985624)
		(width 0.20066)
		(layer "F.Cu")
		(net "M_C_CPU1_SB_DQ<26>")
	)
	(segment
		(start 27.328114 -203.266802)
		(end 28.475178 -203.266802)
		(width 0.20066)
		(layer "F.Cu")
		(net "M_C_CPU1_SB_DQ<26>")
	)
	(segment
		(start 60.593986 -204.708506)
		(end 60.411106 -204.525626)
		(width 0.18288)
		(layer "In6.Cu")
		(net "M_C_CPU1_SB_DQ<26>")
	)
	(segment
		(start 49.449736 -202.84186)
		(end 49.289716 -203.00188)
		(width 0.18288)
		(layer "In6.Cu")
		(net "M_C_CPU1_SB_DQ<26>")
	)
	(segment
		(start 48.756316 -203.585572)
		(end 48.596296 -203.425552)
		(width 0.18288)
		(layer "In6.Cu")
		(net "M_C_CPU1_SB_DQ<26>")
	)
	(segment
		(start 66.140838 -207.971136)
		(end 65.61836 -207.448658)
		(width 0.18288)
		(layer "In6.Cu")
		(net "M_C_CPU1_SB_DQ<26>")
	)
	(segment
		(start 87.958168 -228.948488)
		(end 87.947754 -228.954584)
		(width 0.088646)
		(layer "In6.Cu")
		(net "M_C_CPU1_SB_DQ<26>")
	)
	(segment
		(start 65.61836 -207.448658)
		(end 65.61836 -206.75346)
		(width 0.18288)
		(layer "In6.Cu")
		(net "M_C_CPU1_SB_DQ<26>")
	)
	(segment
		(start 63.595504 -205.375764)
		(end 63.00343 -205.967838)
		(width 0.18288)
		(layer "In6.Cu")
		(net "M_C_CPU1_SB_DQ<26>")
	)
	(segment
		(start 56.84139 -203.662026)
		(end 55.808626 -203.662026)
		(width 0.18288)
		(layer "In6.Cu")
		(net "M_C_CPU1_SB_DQ<26>")
	)
	(segment
		(start 87.110316 -228.459284)
		(end 87.110316 -228.452172)
		(width 0.088646)
		(layer "In6.Cu")
		(net "M_C_CPU1_SB_DQ<26>")
	)
	(segment
		(start 46.629574 -203.54798)
		(end 45.885862 -203.54798)
		(width 0.18288)
		(layer "In6.Cu")
		(net "M_C_CPU1_SB_DQ<26>")
	)
	(segment
		(start 40.48887 -202.578716)
		(end 38.603936 -202.578716)
		(width 0.18288)
		(layer "In6.Cu")
		(net "M_C_CPU1_SB_DQ<26>")
	)
	(segment
		(start 46.771052 -203.689458)
		(end 46.629574 -203.54798)
		(width 0.18288)
		(layer "In6.Cu")
		(net "M_C_CPU1_SB_DQ<26>")
	)
	(segment
		(start 91.339416 -229.28834)
		(end 91.339416 -229.272846)
		(width 0.088646)
		(layer "In6.Cu")
		(net "M_C_CPU1_SB_DQ<26>")
	)
	(segment
		(start 77.907642 -223.80575)
		(end 77.907642 -221.02064)
		(width 0.18288)
		(layer "In6.Cu")
		(net "M_C_CPU1_SB_DQ<26>")
	)
	(segment
		(start 48.596296 -203.425552)
		(end 48.596296 -203.00188)
		(width 0.18288)
		(layer "In6.Cu")
		(net "M_C_CPU1_SB_DQ<26>")
	)
	(segment
		(start 59.720226 -204.525626)
		(end 58.856626 -203.662026)
		(width 0.18288)
		(layer "In6.Cu")
		(net "M_C_CPU1_SB_DQ<26>")
	)
	(segment
		(start 44.41952 -202.802236)
		(end 43.920664 -203.301092)
		(width 0.18288)
		(layer "In6.Cu")
		(net "M_C_CPU1_SB_DQ<26>")
	)
	(segment
		(start 89.287096 -228.957124)
		(end 89.272364 -228.948488)
		(width 0.088646)
		(layer "In6.Cu")
		(net "M_C_CPU1_SB_DQ<26>")
	)
	(segment
		(start 87.11057 -228.474778)
		(end 87.110316 -228.459284)
		(width 0.088646)
		(layer "In6.Cu")
		(net "M_C_CPU1_SB_DQ<26>")
	)
	(segment
		(start 47.14494 -203.689458)
		(end 46.771052 -203.689458)
		(width 0.18288)
		(layer "In6.Cu")
		(net "M_C_CPU1_SB_DQ<26>")
	)
	(segment
		(start 77.907642 -221.02064)
		(end 69.544184 -212.657182)
		(width 0.18288)
		(layer "In6.Cu")
		(net "M_C_CPU1_SB_DQ<26>")
	)
	(segment
		(start 57.20715 -204.573378)
		(end 57.02427 -204.390498)
		(width 0.18288)
		(layer "In6.Cu")
		(net "M_C_CPU1_SB_DQ<26>")
	)
	(segment
		(start 41.902126 -203.301092)
		(end 41.211246 -203.301092)
		(width 0.18288)
		(layer "In6.Cu")
		(net "M_C_CPU1_SB_DQ<26>")
	)
	(segment
		(start 62.512956 -205.735936)
		(end 62.512956 -205.477364)
		(width 0.18288)
		(layer "In6.Cu")
		(net "M_C_CPU1_SB_DQ<26>")
	)
	(segment
		(start 42.595546 -202.407774)
		(end 42.267886 -202.407774)
		(width 0.18288)
		(layer "In6.Cu")
		(net "M_C_CPU1_SB_DQ<26>")
	)
	(segment
		(start 42.085006 -202.590654)
		(end 42.085006 -203.118212)
		(width 0.18288)
		(layer "In6.Cu")
		(net "M_C_CPU1_SB_DQ<26>")
	)
	(segment
		(start 90.226896 -228.957124)
		(end 90.212164 -228.948488)
		(width 0.088646)
		(layer "In6.Cu")
		(net "M_C_CPU1_SB_DQ<26>")
	)
	(segment
		(start 68.162678 -209.321908)
		(end 66.140838 -207.971136)
		(width 0.18288)
		(layer "In6.Cu")
		(net "M_C_CPU1_SB_DQ<26>")
	)
	(segment
		(start 84.583778 -227.326698)
		(end 84.573364 -227.320602)
		(width 0.088646)
		(layer "In6.Cu")
		(net "M_C_CPU1_SB_DQ<26>")
	)
	(segment
		(start 86.078568 -227.320602)
		(end 86.068154 -227.326698)
		(width 0.088646)
		(layer "In6.Cu")
		(net "M_C_CPU1_SB_DQ<26>")
	)
	(segment
		(start 88.347296 -228.957124)
		(end 88.332564 -228.948488)
		(width 0.088646)
		(layer "In6.Cu")
		(net "M_C_CPU1_SB_DQ<26>")
	)
	(segment
		(start 61.284866 -205.16596)
		(end 61.101986 -205.34884)
		(width 0.18288)
		(layer "In6.Cu")
		(net "M_C_CPU1_SB_DQ<26>")
	)
	(segment
		(start 63.00343 -205.967838)
		(end 62.744858 -205.967838)
		(width 0.18288)
		(layer "In6.Cu")
		(net "M_C_CPU1_SB_DQ<26>")
	)
	(segment
		(start 48.596296 -203.00188)
		(end 48.436276 -202.84186)
		(width 0.18288)
		(layer "In6.Cu")
		(net "M_C_CPU1_SB_DQ<26>")
	)
	(segment
		(start 69.544184 -212.657182)
		(end 68.162678 -209.321908)
		(width 0.18288)
		(layer "In6.Cu")
		(net "M_C_CPU1_SB_DQ<26>")
	)
	(segment
		(start 49.289716 -203.00188)
		(end 49.289716 -203.425552)
		(width 0.18288)
		(layer "In6.Cu")
		(net "M_C_CPU1_SB_DQ<26>")
	)
	(segment
		(start 60.593986 -205.144624)
		(end 60.593986 -204.708506)
		(width 0.18288)
		(layer "In6.Cu")
		(net "M_C_CPU1_SB_DQ<26>")
	)
	(segment
		(start 43.920664 -203.301092)
		(end 42.961306 -203.301092)
		(width 0.18288)
		(layer "In6.Cu")
		(net "M_C_CPU1_SB_DQ<26>")
	)
	(segment
		(start 91.160854 -228.953568)
		(end 91.151964 -228.948488)
		(width 0.088646)
		(layer "In6.Cu")
		(net "M_C_CPU1_SB_DQ<26>")
	)
	(segment
		(start 42.085006 -203.118212)
		(end 41.902126 -203.301092)
		(width 0.18288)
		(layer "In6.Cu")
		(net "M_C_CPU1_SB_DQ<26>")
	)
	(segment
		(start 57.02427 -203.844906)
		(end 56.84139 -203.662026)
		(width 0.18288)
		(layer "In6.Cu")
		(net "M_C_CPU1_SB_DQ<26>")
	)
	(segment
		(start 45.885862 -203.54798)
		(end 45.140118 -202.802236)
		(width 0.18288)
		(layer "In6.Cu")
		(net "M_C_CPU1_SB_DQ<26>")
	)
	(segment
		(start 57.89803 -203.662026)
		(end 57.71515 -203.844906)
		(width 0.18288)
		(layer "In6.Cu")
		(net "M_C_CPU1_SB_DQ<26>")
	)
	(segment
		(start 42.778426 -203.118212)
		(end 42.778426 -202.590654)
		(width 0.18288)
		(layer "In6.Cu")
		(net "M_C_CPU1_SB_DQ<26>")
	)
	(segment
		(start 62.841886 -204.889862)
		(end 62.47765 -204.525626)
		(width 0.18288)
		(layer "In6.Cu")
		(net "M_C_CPU1_SB_DQ<26>")
	)
	(segment
		(start 60.798202 -205.34884)
		(end 60.593986 -205.144624)
		(width 0.18288)
		(layer "In6.Cu")
		(net "M_C_CPU1_SB_DQ<26>")
	)
	(segment
		(start 62.744858 -205.967838)
		(end 62.512956 -205.735936)
		(width 0.18288)
		(layer "In6.Cu")
		(net "M_C_CPU1_SB_DQ<26>")
	)
	(segment
		(start 55.808626 -203.662026)
		(end 54.98846 -202.84186)
		(width 0.18288)
		(layer "In6.Cu")
		(net "M_C_CPU1_SB_DQ<26>")
	)
	(segment
		(start 79.513176 -225.411284)
		(end 77.907642 -223.80575)
		(width 0.18288)
		(layer "In6.Cu")
		(net "M_C_CPU1_SB_DQ<26>")
	)
	(segment
		(start 42.267886 -202.407774)
		(end 42.085006 -202.590654)
		(width 0.18288)
		(layer "In6.Cu")
		(net "M_C_CPU1_SB_DQ<26>")
	)
	(segment
		(start 82.479642 -225.411284)
		(end 79.513176 -225.411284)
		(width 0.18288)
		(layer "In6.Cu")
		(net "M_C_CPU1_SB_DQ<26>")
	)
	(segment
		(start 60.411106 -204.525626)
		(end 59.720226 -204.525626)
		(width 0.18288)
		(layer "In6.Cu")
		(net "M_C_CPU1_SB_DQ<26>")
	)
	(segment
		(start 36.98875 -202.845162)
		(end 36.56711 -203.266802)
		(width 0.18288)
		(layer "In6.Cu")
		(net "M_C_CPU1_SB_DQ<26>")
	)
	(segment
		(start 36.56711 -203.266802)
		(end 35.976814 -203.266802)
		(width 0.18288)
		(layer "In6.Cu")
		(net "M_C_CPU1_SB_DQ<26>")
	)
	(segment
		(start 86.640162 -227.659184)
		(end 86.640162 -227.636324)
		(width 0.088646)
		(layer "In6.Cu")
		(net "M_C_CPU1_SB_DQ<26>")
	)
	(segment
		(start 54.98846 -202.84186)
		(end 49.449736 -202.84186)
		(width 0.18288)
		(layer "In6.Cu")
		(net "M_C_CPU1_SB_DQ<26>")
	)
	(segment
		(start 65.61836 -206.75346)
		(end 64.240664 -205.375764)
		(width 0.18288)
		(layer "In6.Cu")
		(net "M_C_CPU1_SB_DQ<26>")
	)
	(segment
		(start 94.066614 -229.762304)
		(end 94.051882 -229.77094)
		(width 0.088646)
		(layer "In6.Cu")
		(net "M_C_CPU1_SB_DQ<26>")
	)
	(segment
		(start 57.71515 -203.844906)
		(end 57.71515 -204.390498)
		(width 0.18288)
		(layer "In6.Cu")
		(net "M_C_CPU1_SB_DQ<26>")
	)
	(segment
		(start 42.961306 -203.301092)
		(end 42.778426 -203.118212)
		(width 0.18288)
		(layer "In6.Cu")
		(net "M_C_CPU1_SB_DQ<26>")
	)
	(segment
		(start 64.240664 -205.375764)
		(end 63.595504 -205.375764)
		(width 0.18288)
		(layer "In6.Cu")
		(net "M_C_CPU1_SB_DQ<26>")
	)
	(segment
		(start 42.778426 -202.590654)
		(end 42.595546 -202.407774)
		(width 0.18288)
		(layer "In6.Cu")
		(net "M_C_CPU1_SB_DQ<26>")
	)
	(segment
		(start 49.289716 -203.425552)
		(end 49.129696 -203.585572)
		(width 0.18288)
		(layer "In6.Cu")
		(net "M_C_CPU1_SB_DQ<26>")
	)
	(segment
		(start 57.71515 -204.390498)
		(end 57.53227 -204.573378)
		(width 0.18288)
		(layer "In6.Cu")
		(net "M_C_CPU1_SB_DQ<26>")
	)
	(segment
		(start 62.841886 -205.148434)
		(end 62.841886 -204.889862)
		(width 0.18288)
		(layer "In6.Cu")
		(net "M_C_CPU1_SB_DQ<26>")
	)
	(segment
		(start 62.47765 -204.525626)
		(end 61.467746 -204.525626)
		(width 0.18288)
		(layer "In6.Cu")
		(net "M_C_CPU1_SB_DQ<26>")
	)
	(segment
		(start 93.126814 -229.762304)
		(end 93.112082 -229.77094)
		(width 0.088646)
		(layer "In6.Cu")
		(net "M_C_CPU1_SB_DQ<26>")
	)
	(segment
		(start 61.101986 -205.34884)
		(end 60.798202 -205.34884)
		(width 0.18288)
		(layer "In6.Cu")
		(net "M_C_CPU1_SB_DQ<26>")
	)
	(segment
		(start 92.187014 -229.762304)
		(end 92.172282 -229.77094)
		(width 0.088646)
		(layer "In6.Cu")
		(net "M_C_CPU1_SB_DQ<26>")
	)
	(segment
		(start 57.53227 -204.573378)
		(end 57.20715 -204.573378)
		(width 0.18288)
		(layer "In6.Cu")
		(net "M_C_CPU1_SB_DQ<26>")
	)
	(segment
		(start 61.284866 -204.708506)
		(end 61.284866 -205.16596)
		(width 0.18288)
		(layer "In6.Cu")
		(net "M_C_CPU1_SB_DQ<26>")
	)
	(segment
		(start 62.512956 -205.477364)
		(end 62.841886 -205.148434)
		(width 0.18288)
		(layer "In6.Cu")
		(net "M_C_CPU1_SB_DQ<26>")
	)
	(segment
		(start 41.211246 -203.301092)
		(end 40.48887 -202.578716)
		(width 0.18288)
		(layer "In6.Cu")
		(net "M_C_CPU1_SB_DQ<26>")
	)
	(segment
		(start 48.436276 -202.84186)
		(end 47.992538 -202.84186)
		(width 0.18288)
		(layer "In6.Cu")
		(net "M_C_CPU1_SB_DQ<26>")
	)
	(segment
		(start 47.992538 -202.84186)
		(end 47.14494 -203.689458)
		(width 0.18288)
		(layer "In6.Cu")
		(net "M_C_CPU1_SB_DQ<26>")
	)
	(segment
		(start 49.129696 -203.585572)
		(end 48.756316 -203.585572)
		(width 0.18288)
		(layer "In6.Cu")
		(net "M_C_CPU1_SB_DQ<26>")
	)
	(segment
		(start 82.636868 -225.411284)
		(end 82.479642 -225.411284)
		(width 0.088646)
		(layer "In6.Cu")
		(net "M_C_CPU1_SB_DQ<26>")
	)
	(segment
		(start 38.603936 -202.578716)
		(end 38.33749 -202.845162)
		(width 0.18288)
		(layer "In6.Cu")
		(net "M_C_CPU1_SB_DQ<26>")
	)
	(segment
		(start 84.45627 -227.230686)
		(end 82.636868 -225.411284)
		(width 0.088646)
		(layer "In6.Cu")
		(net "M_C_CPU1_SB_DQ<26>")
	)
	(segment
		(start 57.02427 -204.390498)
		(end 57.02427 -203.844906)
		(width 0.18288)
		(layer "In6.Cu")
		(net "M_C_CPU1_SB_DQ<26>")
	)
	(segment
		(start 58.856626 -203.662026)
		(end 57.89803 -203.662026)
		(width 0.18288)
		(layer "In6.Cu")
		(net "M_C_CPU1_SB_DQ<26>")
	)
	(segment
		(start 45.140118 -202.802236)
		(end 44.41952 -202.802236)
		(width 0.18288)
		(layer "In6.Cu")
		(net "M_C_CPU1_SB_DQ<26>")
	)
	(segment
		(start 61.467746 -204.525626)
		(end 61.284866 -204.708506)
		(width 0.18288)
		(layer "In6.Cu")
		(net "M_C_CPU1_SB_DQ<26>")
	)
	(segment
		(start 38.33749 -202.845162)
		(end 36.98875 -202.845162)
		(width 0.18288)
		(layer "In6.Cu")
		(net "M_C_CPU1_SB_DQ<26>")
	)
	(arc
		(start 86.922864 -228.134672)
		(mid 86.719383 -227.933868)
		(end 86.640162 -227.659184)
		(width 0.088646)
		(layer "In6.Cu")
		(net "M_C_CPU1_SB_DQ<26>")
	)
	(arc
		(start 85.138514 -227.320602)
		(mid 84.861955 -227.396345)
		(end 84.583778 -227.326698)
		(width 0.088646)
		(layer "In6.Cu")
		(net "M_C_CPU1_SB_DQ<26>")
	)
	(arc
		(start 96.603566 -229.272846)
		(mid 96.303596 -229.574058)
		(end 95.889826 -229.671626)
		(width 0.088646)
		(layer "In6.Cu")
		(net "M_C_CPU1_SB_DQ<26>")
	)
	(arc
		(start 86.452964 -227.320602)
		(mid 86.265766 -227.270459)
		(end 86.078568 -227.320602)
		(width 0.088646)
		(layer "In6.Cu")
		(net "M_C_CPU1_SB_DQ<26>")
	)
	(arc
		(start 95.006414 -229.762304)
		(mid 94.723712 -229.83808)
		(end 94.44101 -229.762304)
		(width 0.088646)
		(layer "In6.Cu")
		(net "M_C_CPU1_SB_DQ<26>")
	)
	(arc
		(start 86.068154 -227.326698)
		(mid 85.789722 -227.396544)
		(end 85.51291 -227.320602)
		(width 0.088646)
		(layer "In6.Cu")
		(net "M_C_CPU1_SB_DQ<26>")
	)
	(arc
		(start 93.50121 -229.762304)
		(mid 93.314012 -229.712161)
		(end 93.126814 -229.762304)
		(width 0.088646)
		(layer "In6.Cu")
		(net "M_C_CPU1_SB_DQ<26>")
	)
	(arc
		(start 90.777568 -228.948488)
		(mid 90.503369 -229.024323)
		(end 90.226896 -228.957124)
		(width 0.088646)
		(layer "In6.Cu")
		(net "M_C_CPU1_SB_DQ<26>")
	)
	(arc
		(start 94.44101 -229.762304)
		(mid 94.253812 -229.712161)
		(end 94.066614 -229.762304)
		(width 0.088646)
		(layer "In6.Cu")
		(net "M_C_CPU1_SB_DQ<26>")
	)
	(arc
		(start 93.112082 -229.77094)
		(mid 92.835607 -229.83826)
		(end 92.56141 -229.762304)
		(width 0.088646)
		(layer "In6.Cu")
		(net "M_C_CPU1_SB_DQ<26>")
	)
	(arc
		(start 87.947754 -228.954584)
		(mid 87.669322 -229.02443)
		(end 87.39251 -228.948488)
		(width 0.088646)
		(layer "In6.Cu")
		(net "M_C_CPU1_SB_DQ<26>")
	)
	(arc
		(start 89.837768 -228.948488)
		(mid 89.563569 -229.024323)
		(end 89.287096 -228.957124)
		(width 0.088646)
		(layer "In6.Cu")
		(net "M_C_CPU1_SB_DQ<26>")
	)
	(arc
		(start 91.62161 -229.762304)
		(mid 91.418787 -229.562073)
		(end 91.339416 -229.28834)
		(width 0.088646)
		(layer "In6.Cu")
		(net "M_C_CPU1_SB_DQ<26>")
	)
	(arc
		(start 92.56141 -229.762304)
		(mid 92.374212 -229.712161)
		(end 92.187014 -229.762304)
		(width 0.088646)
		(layer "In6.Cu")
		(net "M_C_CPU1_SB_DQ<26>")
	)
	(arc
		(start 86.640162 -227.636324)
		(mid 86.587892 -227.453959)
		(end 86.452964 -227.320602)
		(width 0.088646)
		(layer "In6.Cu")
		(net "M_C_CPU1_SB_DQ<26>")
	)
	(arc
		(start 85.51291 -227.320602)
		(mid 85.325712 -227.270459)
		(end 85.138514 -227.320602)
		(width 0.088646)
		(layer "In6.Cu")
		(net "M_C_CPU1_SB_DQ<26>")
	)
	(arc
		(start 84.573364 -227.320602)
		(mid 84.511875 -227.279476)
		(end 84.45627 -227.230686)
		(width 0.088646)
		(layer "In6.Cu")
		(net "M_C_CPU1_SB_DQ<26>")
	)
	(arc
		(start 87.110316 -228.452172)
		(mid 87.05834 -228.268773)
		(end 86.922864 -228.134672)
		(width 0.088646)
		(layer "In6.Cu")
		(net "M_C_CPU1_SB_DQ<26>")
	)
	(arc
		(start 95.131382 -229.717346)
		(mid 95.066885 -229.734232)
		(end 95.006414 -229.762304)
		(width 0.088646)
		(layer "In6.Cu")
		(net "M_C_CPU1_SB_DQ<26>")
	)
	(arc
		(start 88.332564 -228.948488)
		(mid 88.145366 -228.898345)
		(end 87.958168 -228.948488)
		(width 0.088646)
		(layer "In6.Cu")
		(net "M_C_CPU1_SB_DQ<26>")
	)
	(arc
		(start 92.172282 -229.77094)
		(mid 91.895807 -229.83826)
		(end 91.62161 -229.762304)
		(width 0.088646)
		(layer "In6.Cu")
		(net "M_C_CPU1_SB_DQ<26>")
	)
	(arc
		(start 91.151964 -228.948488)
		(mid 90.964766 -228.898345)
		(end 90.777568 -228.948488)
		(width 0.088646)
		(layer "In6.Cu")
		(net "M_C_CPU1_SB_DQ<26>")
	)
	(arc
		(start 90.212164 -228.948488)
		(mid 90.024966 -228.898345)
		(end 89.837768 -228.948488)
		(width 0.088646)
		(layer "In6.Cu")
		(net "M_C_CPU1_SB_DQ<26>")
	)
	(arc
		(start 94.051882 -229.77094)
		(mid 93.775407 -229.83826)
		(end 93.50121 -229.762304)
		(width 0.088646)
		(layer "In6.Cu")
		(net "M_C_CPU1_SB_DQ<26>")
	)
	(arc
		(start 95.889826 -229.671626)
		(mid 95.509383 -229.674228)
		(end 95.131382 -229.717346)
		(width 0.088646)
		(layer "In6.Cu")
		(net "M_C_CPU1_SB_DQ<26>")
	)
	(arc
		(start 87.39251 -228.948488)
		(mid 87.189932 -228.748315)
		(end 87.11057 -228.474778)
		(width 0.088646)
		(layer "In6.Cu")
		(net "M_C_CPU1_SB_DQ<26>")
	)
	(arc
		(start 88.897968 -228.948488)
		(mid 88.623769 -229.024323)
		(end 88.347296 -228.957124)
		(width 0.088646)
		(layer "In6.Cu")
		(net "M_C_CPU1_SB_DQ<26>")
	)
	(arc
		(start 89.272364 -228.948488)
		(mid 89.085166 -228.898345)
		(end 88.897968 -228.948488)
		(width 0.088646)
		(layer "In6.Cu")
		(net "M_C_CPU1_SB_DQ<26>")
	)
	(arc
		(start 91.339416 -229.272846)
		(mid 91.291737 -229.089946)
		(end 91.160854 -228.953568)
		(width 0.088646)
		(layer "In6.Cu")
		(net "M_C_CPU1_SB_DQ<26>")
	)
	(segment
		(start 25.27808 -202.627992)
		(end 25.432512 -202.47356)
		(width 0.20066)
		(layer "F.Cu")
		(net "M_C_CPU1_SB_DQ<25>")
	)
	(segment
		(start 26.2128 -201.991722)
		(end 28.198318 -201.991722)
		(width 0.1016)
		(layer "F.Cu")
		(net "M_C_CPU1_SB_DQ<25>")
	)
	(segment
		(start 24.562308 -202.416664)
		(end 24.773636 -202.627992)
		(width 0.20066)
		(layer "F.Cu")
		(net "M_C_CPU1_SB_DQ<25>")
	)
	(segment
		(start 25.595072 -201.982832)
		(end 26.20391 -201.982832)
		(width 0.20066)
		(layer "F.Cu")
		(net "M_C_CPU1_SB_DQ<25>")
	)
	(segment
		(start 31.876746 -202.416664)
		(end 30.771846 -202.416664)
		(width 0.20066)
		(layer "F.Cu")
		(net "M_C_CPU1_SB_DQ<25>")
	)
	(segment
		(start 25.432512 -202.145392)
		(end 25.595072 -201.982832)
		(width 0.20066)
		(layer "F.Cu")
		(net "M_C_CPU1_SB_DQ<25>")
	)
	(segment
		(start 23.228046 -202.416664)
		(end 24.562308 -202.416664)
		(width 0.20066)
		(layer "F.Cu")
		(net "M_C_CPU1_SB_DQ<25>")
	)
	(segment
		(start 28.529026 -201.991722)
		(end 28.707588 -201.991722)
		(width 0.20066)
		(layer "F.Cu")
		(net "M_C_CPU1_SB_DQ<25>")
	)
	(segment
		(start 25.432512 -202.47356)
		(end 25.432512 -202.145392)
		(width 0.20066)
		(layer "F.Cu")
		(net "M_C_CPU1_SB_DQ<25>")
	)
	(segment
		(start 29.13253 -202.416664)
		(end 30.771846 -202.416664)
		(width 0.20066)
		(layer "F.Cu")
		(net "M_C_CPU1_SB_DQ<25>")
	)
	(segment
		(start 95.193866 -228.99497)
		(end 95.193612 -228.994716)
		(width 0.20066)
		(layer "F.Cu")
		(net "M_C_CPU1_SB_DQ<25>")
	)
	(segment
		(start 26.20391 -201.982832)
		(end 26.2128 -201.991722)
		(width 0.1016)
		(layer "F.Cu")
		(net "M_C_CPU1_SB_DQ<25>")
	)
	(segment
		(start 24.773636 -202.627992)
		(end 25.27808 -202.627992)
		(width 0.20066)
		(layer "F.Cu")
		(net "M_C_CPU1_SB_DQ<25>")
	)
	(segment
		(start 28.707588 -201.991722)
		(end 29.13253 -202.416664)
		(width 0.20066)
		(layer "F.Cu")
		(net "M_C_CPU1_SB_DQ<25>")
	)
	(segment
		(start 28.198318 -201.991722)
		(end 28.529026 -201.991722)
		(width 0.101854)
		(layer "F.Cu")
		(net "M_C_CPU1_SB_DQ<25>")
	)
	(segment
		(start 95.193612 -228.994716)
		(end 95.193612 -228.45903)
		(width 0.20066)
		(layer "F.Cu")
		(net "M_C_CPU1_SB_DQ<25>")
	)
	(segment
		(start 42.234358 -200.832212)
		(end 41.92524 -201.14133)
		(width 0.18288)
		(layer "In6.Cu")
		(net "M_C_CPU1_SB_DQ<25>")
	)
	(segment
		(start 53.049678 -201.141838)
		(end 52.724812 -200.816972)
		(width 0.18288)
		(layer "In6.Cu")
		(net "M_C_CPU1_SB_DQ<25>")
	)
	(segment
		(start 54.111652 -200.816972)
		(end 53.743098 -200.816972)
		(width 0.18288)
		(layer "In6.Cu")
		(net "M_C_CPU1_SB_DQ<25>")
	)
	(segment
		(start 32.751268 -201.83094)
		(end 32.46247 -201.83094)
		(width 0.18288)
		(layer "In6.Cu")
		(net "M_C_CPU1_SB_DQ<25>")
	)
	(segment
		(start 34.015426 -201.83094)
		(end 33.810448 -201.83094)
		(width 0.18288)
		(layer "In6.Cu")
		(net "M_C_CPU1_SB_DQ<25>")
	)
	(segment
		(start 39.378128 -200.842372)
		(end 39.07917 -201.14133)
		(width 0.18288)
		(layer "In6.Cu")
		(net "M_C_CPU1_SB_DQ<25>")
	)
	(segment
		(start 61.127386 -203.46289)
		(end 60.802266 -203.46289)
		(width 0.18288)
		(layer "In6.Cu")
		(net "M_C_CPU1_SB_DQ<25>")
	)
	(segment
		(start 60.802266 -203.46289)
		(end 60.619386 -203.28001)
		(width 0.18288)
		(layer "In6.Cu")
		(net "M_C_CPU1_SB_DQ<25>")
	)
	(segment
		(start 55.884826 -201.884026)
		(end 55.142638 -201.141838)
		(width 0.18288)
		(layer "In6.Cu")
		(net "M_C_CPU1_SB_DQ<25>")
	)
	(segment
		(start 91.809062 -228.45903)
		(end 91.809062 -228.450394)
		(width 0.088646)
		(layer "In6.Cu")
		(net "M_C_CPU1_SB_DQ<25>")
	)
	(segment
		(start 55.142638 -201.141838)
		(end 54.436518 -201.141838)
		(width 0.18288)
		(layer "In6.Cu")
		(net "M_C_CPU1_SB_DQ<25>")
	)
	(segment
		(start 48.155606 -201.141838)
		(end 47.305722 -201.991722)
		(width 0.18288)
		(layer "In6.Cu")
		(net "M_C_CPU1_SB_DQ<25>")
	)
	(segment
		(start 78.903322 -223.393254)
		(end 78.903322 -220.544644)
		(width 0.18288)
		(layer "In6.Cu")
		(net "M_C_CPU1_SB_DQ<25>")
	)
	(segment
		(start 79.925672 -224.415604)
		(end 78.903322 -223.393254)
		(width 0.18288)
		(layer "In6.Cu")
		(net "M_C_CPU1_SB_DQ<25>")
	)
	(segment
		(start 62.412626 -202.798426)
		(end 61.493146 -202.798426)
		(width 0.18288)
		(layer "In6.Cu")
		(net "M_C_CPU1_SB_DQ<25>")
	)
	(segment
		(start 58.00598 -201.884026)
		(end 57.8231 -202.066906)
		(width 0.18288)
		(layer "In6.Cu")
		(net "M_C_CPU1_SB_DQ<25>")
	)
	(segment
		(start 37.439092 -201.99096)
		(end 34.175446 -201.99096)
		(width 0.18288)
		(layer "In6.Cu")
		(net "M_C_CPU1_SB_DQ<25>")
	)
	(segment
		(start 40.071548 -201.14133)
		(end 39.77259 -200.842372)
		(width 0.18288)
		(layer "In6.Cu")
		(net "M_C_CPU1_SB_DQ<25>")
	)
	(segment
		(start 56.94934 -201.884026)
		(end 55.884826 -201.884026)
		(width 0.18288)
		(layer "In6.Cu")
		(net "M_C_CPU1_SB_DQ<25>")
	)
	(segment
		(start 57.64022 -202.57643)
		(end 57.3151 -202.57643)
		(width 0.18288)
		(layer "In6.Cu")
		(net "M_C_CPU1_SB_DQ<25>")
	)
	(segment
		(start 59.745626 -202.798426)
		(end 58.831226 -201.884026)
		(width 0.18288)
		(layer "In6.Cu")
		(net "M_C_CPU1_SB_DQ<25>")
	)
	(segment
		(start 86.548214 -226.506786)
		(end 86.5378 -226.512882)
		(width 0.088646)
		(layer "In6.Cu")
		(net "M_C_CPU1_SB_DQ<25>")
	)
	(segment
		(start 46.789594 -201.991722)
		(end 45.939202 -201.14133)
		(width 0.18288)
		(layer "In6.Cu")
		(net "M_C_CPU1_SB_DQ<25>")
	)
	(segment
		(start 33.810448 -201.83094)
		(end 33.627568 -201.64806)
		(width 0.18288)
		(layer "In6.Cu")
		(net "M_C_CPU1_SB_DQ<25>")
	)
	(segment
		(start 82.479642 -224.415604)
		(end 79.925672 -224.415604)
		(width 0.18288)
		(layer "In6.Cu")
		(net "M_C_CPU1_SB_DQ<25>")
	)
	(segment
		(start 45.939202 -201.14133)
		(end 42.927778 -201.14133)
		(width 0.18288)
		(layer "In6.Cu")
		(net "M_C_CPU1_SB_DQ<25>")
	)
	(segment
		(start 33.117028 -201.19213)
		(end 32.934148 -201.37501)
		(width 0.18288)
		(layer "In6.Cu")
		(net "M_C_CPU1_SB_DQ<25>")
	)
	(segment
		(start 84.49691 -226.45624)
		(end 84.1248 -226.08413)
		(width 0.088646)
		(layer "In6.Cu")
		(net "M_C_CPU1_SB_DQ<25>")
	)
	(segment
		(start 52.031392 -201.141838)
		(end 48.155606 -201.141838)
		(width 0.18288)
		(layer "In6.Cu")
		(net "M_C_CPU1_SB_DQ<25>")
	)
	(segment
		(start 57.8231 -202.066906)
		(end 57.8231 -202.39355)
		(width 0.18288)
		(layer "In6.Cu")
		(net "M_C_CPU1_SB_DQ<25>")
	)
	(segment
		(start 58.831226 -201.884026)
		(end 58.00598 -201.884026)
		(width 0.18288)
		(layer "In6.Cu")
		(net "M_C_CPU1_SB_DQ<25>")
	)
	(segment
		(start 82.7024 -224.415604)
		(end 82.479642 -224.415604)
		(width 0.088646)
		(layer "In6.Cu")
		(net "M_C_CPU1_SB_DQ<25>")
	)
	(segment
		(start 86.9315 -226.511866)
		(end 86.92261 -226.506786)
		(width 0.088646)
		(layer "In6.Cu")
		(net "M_C_CPU1_SB_DQ<25>")
	)
	(segment
		(start 63.225426 -203.611226)
		(end 62.412626 -202.798426)
		(width 0.18288)
		(layer "In6.Cu")
		(net "M_C_CPU1_SB_DQ<25>")
	)
	(segment
		(start 64.076326 -203.611226)
		(end 63.225426 -203.611226)
		(width 0.18288)
		(layer "In6.Cu")
		(net "M_C_CPU1_SB_DQ<25>")
	)
	(segment
		(start 32.934148 -201.37501)
		(end 32.934148 -201.64806)
		(width 0.18288)
		(layer "In6.Cu")
		(net "M_C_CPU1_SB_DQ<25>")
	)
	(segment
		(start 57.3151 -202.57643)
		(end 57.13222 -202.39355)
		(width 0.18288)
		(layer "In6.Cu")
		(net "M_C_CPU1_SB_DQ<25>")
	)
	(segment
		(start 42.927778 -201.14133)
		(end 42.61866 -200.832212)
		(width 0.18288)
		(layer "In6.Cu")
		(net "M_C_CPU1_SB_DQ<25>")
	)
	(segment
		(start 47.305722 -201.991722)
		(end 46.789594 -201.991722)
		(width 0.18288)
		(layer "In6.Cu")
		(net "M_C_CPU1_SB_DQ<25>")
	)
	(segment
		(start 34.175446 -201.99096)
		(end 34.015426 -201.83094)
		(width 0.18288)
		(layer "In6.Cu")
		(net "M_C_CPU1_SB_DQ<25>")
	)
	(segment
		(start 53.418232 -201.141838)
		(end 53.049678 -201.141838)
		(width 0.18288)
		(layer "In6.Cu")
		(net "M_C_CPU1_SB_DQ<25>")
	)
	(segment
		(start 32.46247 -201.83094)
		(end 31.876746 -202.416664)
		(width 0.18288)
		(layer "In6.Cu")
		(net "M_C_CPU1_SB_DQ<25>")
	)
	(segment
		(start 57.13222 -202.39355)
		(end 57.13222 -202.066906)
		(width 0.18288)
		(layer "In6.Cu")
		(net "M_C_CPU1_SB_DQ<25>")
	)
	(segment
		(start 39.77259 -200.842372)
		(end 39.378128 -200.842372)
		(width 0.18288)
		(layer "In6.Cu")
		(net "M_C_CPU1_SB_DQ<25>")
	)
	(segment
		(start 66.419984 -205.350364)
		(end 65.815464 -205.350364)
		(width 0.18288)
		(layer "In6.Cu")
		(net "M_C_CPU1_SB_DQ<25>")
	)
	(segment
		(start 87.39251 -227.320602)
		(end 87.386414 -227.317046)
		(width 0.088646)
		(layer "In6.Cu")
		(net "M_C_CPU1_SB_DQ<25>")
	)
	(segment
		(start 52.356258 -200.816972)
		(end 52.031392 -201.141838)
		(width 0.18288)
		(layer "In6.Cu")
		(net "M_C_CPU1_SB_DQ<25>")
	)
	(segment
		(start 91.247468 -228.134672)
		(end 91.237054 -228.140768)
		(width 0.088646)
		(layer "In6.Cu")
		(net "M_C_CPU1_SB_DQ<25>")
	)
	(segment
		(start 68.491608 -207.421988)
		(end 66.419984 -205.350364)
		(width 0.18288)
		(layer "In6.Cu")
		(net "M_C_CPU1_SB_DQ<25>")
	)
	(segment
		(start 53.743098 -200.816972)
		(end 53.418232 -201.141838)
		(width 0.18288)
		(layer "In6.Cu")
		(net "M_C_CPU1_SB_DQ<25>")
	)
	(segment
		(start 61.310266 -202.981306)
		(end 61.310266 -203.28001)
		(width 0.18288)
		(layer "In6.Cu")
		(net "M_C_CPU1_SB_DQ<25>")
	)
	(segment
		(start 42.61866 -200.832212)
		(end 42.234358 -200.832212)
		(width 0.18288)
		(layer "In6.Cu")
		(net "M_C_CPU1_SB_DQ<25>")
	)
	(segment
		(start 52.724812 -200.816972)
		(end 52.356258 -200.816972)
		(width 0.18288)
		(layer "In6.Cu")
		(net "M_C_CPU1_SB_DQ<25>")
	)
	(segment
		(start 92.091764 -228.948488)
		(end 92.085668 -228.944932)
		(width 0.088646)
		(layer "In6.Cu")
		(net "M_C_CPU1_SB_DQ<25>")
	)
	(segment
		(start 60.436506 -202.798426)
		(end 59.745626 -202.798426)
		(width 0.18288)
		(layer "In6.Cu")
		(net "M_C_CPU1_SB_DQ<25>")
	)
	(segment
		(start 78.903322 -220.544644)
		(end 70.4088 -212.050122)
		(width 0.18288)
		(layer "In6.Cu")
		(net "M_C_CPU1_SB_DQ<25>")
	)
	(segment
		(start 84.1248 -225.838004)
		(end 82.7024 -224.415604)
		(width 0.088646)
		(layer "In6.Cu")
		(net "M_C_CPU1_SB_DQ<25>")
	)
	(segment
		(start 33.627568 -201.64806)
		(end 33.627568 -201.37501)
		(width 0.18288)
		(layer "In6.Cu")
		(net "M_C_CPU1_SB_DQ<25>")
	)
	(segment
		(start 57.13222 -202.066906)
		(end 56.94934 -201.884026)
		(width 0.18288)
		(layer "In6.Cu")
		(net "M_C_CPU1_SB_DQ<25>")
	)
	(segment
		(start 70.4088 -212.050122)
		(end 68.491608 -207.421988)
		(width 0.18288)
		(layer "In6.Cu")
		(net "M_C_CPU1_SB_DQ<25>")
	)
	(segment
		(start 38.288722 -201.14133)
		(end 37.439092 -201.99096)
		(width 0.18288)
		(layer "In6.Cu")
		(net "M_C_CPU1_SB_DQ<25>")
	)
	(segment
		(start 61.493146 -202.798426)
		(end 61.310266 -202.981306)
		(width 0.18288)
		(layer "In6.Cu")
		(net "M_C_CPU1_SB_DQ<25>")
	)
	(segment
		(start 54.436518 -201.141838)
		(end 54.111652 -200.816972)
		(width 0.18288)
		(layer "In6.Cu")
		(net "M_C_CPU1_SB_DQ<25>")
	)
	(segment
		(start 93.046296 -228.957124)
		(end 93.031564 -228.948488)
		(width 0.088646)
		(layer "In6.Cu")
		(net "M_C_CPU1_SB_DQ<25>")
	)
	(segment
		(start 89.367614 -228.134672)
		(end 89.352882 -228.143308)
		(width 0.088646)
		(layer "In6.Cu")
		(net "M_C_CPU1_SB_DQ<25>")
	)
	(segment
		(start 90.307414 -228.134672)
		(end 90.292682 -228.143308)
		(width 0.088646)
		(layer "In6.Cu")
		(net "M_C_CPU1_SB_DQ<25>")
	)
	(segment
		(start 61.310266 -203.28001)
		(end 61.127386 -203.46289)
		(width 0.18288)
		(layer "In6.Cu")
		(net "M_C_CPU1_SB_DQ<25>")
	)
	(segment
		(start 33.444688 -201.19213)
		(end 33.117028 -201.19213)
		(width 0.18288)
		(layer "In6.Cu")
		(net "M_C_CPU1_SB_DQ<25>")
	)
	(segment
		(start 84.855812 -226.45624)
		(end 84.49691 -226.45624)
		(width 0.088646)
		(layer "In6.Cu")
		(net "M_C_CPU1_SB_DQ<25>")
	)
	(segment
		(start 33.627568 -201.37501)
		(end 33.444688 -201.19213)
		(width 0.18288)
		(layer "In6.Cu")
		(net "M_C_CPU1_SB_DQ<25>")
	)
	(segment
		(start 65.815464 -205.350364)
		(end 64.076326 -203.611226)
		(width 0.18288)
		(layer "In6.Cu")
		(net "M_C_CPU1_SB_DQ<25>")
	)
	(segment
		(start 57.8231 -202.39355)
		(end 57.64022 -202.57643)
		(width 0.18288)
		(layer "In6.Cu")
		(net "M_C_CPU1_SB_DQ<25>")
	)
	(segment
		(start 93.981778 -228.954584)
		(end 93.971364 -228.948488)
		(width 0.088646)
		(layer "In6.Cu")
		(net "M_C_CPU1_SB_DQ<25>")
	)
	(segment
		(start 32.934148 -201.64806)
		(end 32.751268 -201.83094)
		(width 0.18288)
		(layer "In6.Cu")
		(net "M_C_CPU1_SB_DQ<25>")
	)
	(segment
		(start 41.92524 -201.14133)
		(end 40.071548 -201.14133)
		(width 0.18288)
		(layer "In6.Cu")
		(net "M_C_CPU1_SB_DQ<25>")
	)
	(segment
		(start 87.579962 -227.65258)
		(end 87.579962 -227.64496)
		(width 0.088646)
		(layer "In6.Cu")
		(net "M_C_CPU1_SB_DQ<25>")
	)
	(segment
		(start 60.619386 -202.981306)
		(end 60.436506 -202.798426)
		(width 0.18288)
		(layer "In6.Cu")
		(net "M_C_CPU1_SB_DQ<25>")
	)
	(segment
		(start 39.07917 -201.14133)
		(end 38.288722 -201.14133)
		(width 0.18288)
		(layer "In6.Cu")
		(net "M_C_CPU1_SB_DQ<25>")
	)
	(segment
		(start 88.427814 -228.134672)
		(end 88.4174 -228.140768)
		(width 0.088646)
		(layer "In6.Cu")
		(net "M_C_CPU1_SB_DQ<25>")
	)
	(segment
		(start 87.4014 -227.325682)
		(end 87.39251 -227.320602)
		(width 0.088646)
		(layer "In6.Cu")
		(net "M_C_CPU1_SB_DQ<25>")
	)
	(segment
		(start 60.619386 -203.28001)
		(end 60.619386 -202.981306)
		(width 0.18288)
		(layer "In6.Cu")
		(net "M_C_CPU1_SB_DQ<25>")
	)
	(segment
		(start 84.1248 -226.08413)
		(end 84.1248 -225.838004)
		(width 0.088646)
		(layer "In6.Cu")
		(net "M_C_CPU1_SB_DQ<25>")
	)
	(segment
		(start 92.106496 -228.957124)
		(end 92.091764 -228.948488)
		(width 0.088646)
		(layer "In6.Cu")
		(net "M_C_CPU1_SB_DQ<25>")
	)
	(arc
		(start 94.536514 -228.948488)
		(mid 94.259955 -229.024231)
		(end 93.981778 -228.954584)
		(width 0.088646)
		(layer "In6.Cu")
		(net "M_C_CPU1_SB_DQ<25>")
	)
	(arc
		(start 88.4174 -228.140768)
		(mid 88.139222 -228.21046)
		(end 87.862664 -228.134672)
		(width 0.088646)
		(layer "In6.Cu")
		(net "M_C_CPU1_SB_DQ<25>")
	)
	(arc
		(start 95.193612 -228.45903)
		(mid 94.87933 -228.722914)
		(end 94.536514 -228.948488)
		(width 0.088646)
		(layer "In6.Cu")
		(net "M_C_CPU1_SB_DQ<25>")
	)
	(arc
		(start 92.085668 -228.944932)
		(mid 91.883081 -228.738581)
		(end 91.809062 -228.45903)
		(width 0.088646)
		(layer "In6.Cu")
		(net "M_C_CPU1_SB_DQ<25>")
	)
	(arc
		(start 92.657168 -228.948488)
		(mid 92.382969 -229.024323)
		(end 92.106496 -228.957124)
		(width 0.088646)
		(layer "In6.Cu")
		(net "M_C_CPU1_SB_DQ<25>")
	)
	(arc
		(start 90.292682 -228.143308)
		(mid 90.016241 -228.210474)
		(end 89.74201 -228.134672)
		(width 0.088646)
		(layer "In6.Cu")
		(net "M_C_CPU1_SB_DQ<25>")
	)
	(arc
		(start 89.352882 -228.143308)
		(mid 89.076441 -228.210474)
		(end 88.80221 -228.134672)
		(width 0.088646)
		(layer "In6.Cu")
		(net "M_C_CPU1_SB_DQ<25>")
	)
	(arc
		(start 85.983064 -226.506786)
		(mid 85.795866 -226.456643)
		(end 85.608668 -226.506786)
		(width 0.088646)
		(layer "In6.Cu")
		(net "M_C_CPU1_SB_DQ<25>")
	)
	(arc
		(start 89.74201 -228.134672)
		(mid 89.554812 -228.084529)
		(end 89.367614 -228.134672)
		(width 0.088646)
		(layer "In6.Cu")
		(net "M_C_CPU1_SB_DQ<25>")
	)
	(arc
		(start 87.579962 -227.64496)
		(mid 87.532283 -227.46206)
		(end 87.4014 -227.325682)
		(width 0.088646)
		(layer "In6.Cu")
		(net "M_C_CPU1_SB_DQ<25>")
	)
	(arc
		(start 88.80221 -228.134672)
		(mid 88.615012 -228.084529)
		(end 88.427814 -228.134672)
		(width 0.088646)
		(layer "In6.Cu")
		(net "M_C_CPU1_SB_DQ<25>")
	)
	(arc
		(start 85.608668 -226.506786)
		(mid 85.331855 -226.582656)
		(end 85.053424 -226.512882)
		(width 0.088646)
		(layer "In6.Cu")
		(net "M_C_CPU1_SB_DQ<25>")
	)
	(arc
		(start 86.5378 -226.512882)
		(mid 86.259622 -226.582605)
		(end 85.983064 -226.506786)
		(width 0.088646)
		(layer "In6.Cu")
		(net "M_C_CPU1_SB_DQ<25>")
	)
	(arc
		(start 87.110062 -226.831144)
		(mid 87.062383 -226.648244)
		(end 86.9315 -226.511866)
		(width 0.088646)
		(layer "In6.Cu")
		(net "M_C_CPU1_SB_DQ<25>")
	)
	(arc
		(start 91.621864 -228.134672)
		(mid 91.434666 -228.084529)
		(end 91.247468 -228.134672)
		(width 0.088646)
		(layer "In6.Cu")
		(net "M_C_CPU1_SB_DQ<25>")
	)
	(arc
		(start 91.237054 -228.140768)
		(mid 90.958622 -228.210582)
		(end 90.68181 -228.134672)
		(width 0.088646)
		(layer "In6.Cu")
		(net "M_C_CPU1_SB_DQ<25>")
	)
	(arc
		(start 93.031564 -228.948488)
		(mid 92.844366 -228.898345)
		(end 92.657168 -228.948488)
		(width 0.088646)
		(layer "In6.Cu")
		(net "M_C_CPU1_SB_DQ<25>")
	)
	(arc
		(start 85.053424 -226.512882)
		(mid 84.95858 -226.470731)
		(end 84.855812 -226.45624)
		(width 0.088646)
		(layer "In6.Cu")
		(net "M_C_CPU1_SB_DQ<25>")
	)
	(arc
		(start 93.596968 -228.948488)
		(mid 93.322769 -229.024323)
		(end 93.046296 -228.957124)
		(width 0.088646)
		(layer "In6.Cu")
		(net "M_C_CPU1_SB_DQ<25>")
	)
	(arc
		(start 87.386414 -227.317046)
		(mid 87.184001 -227.110633)
		(end 87.110062 -226.831144)
		(width 0.088646)
		(layer "In6.Cu")
		(net "M_C_CPU1_SB_DQ<25>")
	)
	(arc
		(start 90.68181 -228.134672)
		(mid 90.494612 -228.084529)
		(end 90.307414 -228.134672)
		(width 0.088646)
		(layer "In6.Cu")
		(net "M_C_CPU1_SB_DQ<25>")
	)
	(arc
		(start 87.862664 -228.134672)
		(mid 87.657592 -227.930993)
		(end 87.579962 -227.65258)
		(width 0.088646)
		(layer "In6.Cu")
		(net "M_C_CPU1_SB_DQ<25>")
	)
	(arc
		(start 93.971364 -228.948488)
		(mid 93.784166 -228.898345)
		(end 93.596968 -228.948488)
		(width 0.088646)
		(layer "In6.Cu")
		(net "M_C_CPU1_SB_DQ<25>")
	)
	(arc
		(start 91.809062 -228.450394)
		(mid 91.756792 -228.268029)
		(end 91.621864 -228.134672)
		(width 0.088646)
		(layer "In6.Cu")
		(net "M_C_CPU1_SB_DQ<25>")
	)
	(arc
		(start 86.92261 -226.506786)
		(mid 86.735412 -226.456643)
		(end 86.548214 -226.506786)
		(width 0.088646)
		(layer "In6.Cu")
		(net "M_C_CPU1_SB_DQ<25>")
	)
	(segment
		(start 95.663512 -229.808786)
		(end 95.663766 -229.808532)
		(width 0.20066)
		(layer "F.Cu")
		(net "M_C_CPU1_SB_DQ<24>")
	)
	(segment
		(start 24.562308 -204.116686)
		(end 24.801068 -204.355446)
		(width 0.20066)
		(layer "F.Cu")
		(net "M_C_CPU1_SB_DQ<24>")
	)
	(segment
		(start 26.459942 -203.691744)
		(end 28.529026 -203.691744)
		(width 0.1016)
		(layer "F.Cu")
		(net "M_C_CPU1_SB_DQ<24>")
	)
	(segment
		(start 26.20391 -203.683616)
		(end 26.212038 -203.691744)
		(width 0.101854)
		(layer "F.Cu")
		(net "M_C_CPU1_SB_DQ<24>")
	)
	(segment
		(start 28.529026 -203.691744)
		(end 28.977844 -203.691744)
		(width 0.20066)
		(layer "F.Cu")
		(net "M_C_CPU1_SB_DQ<24>")
	)
	(segment
		(start 31.876746 -204.116686)
		(end 30.771846 -204.116686)
		(width 0.20066)
		(layer "F.Cu")
		(net "M_C_CPU1_SB_DQ<24>")
	)
	(segment
		(start 25.432512 -204.182726)
		(end 25.432512 -203.893166)
		(width 0.20066)
		(layer "F.Cu")
		(net "M_C_CPU1_SB_DQ<24>")
	)
	(segment
		(start 23.228046 -204.116686)
		(end 24.562308 -204.116686)
		(width 0.20066)
		(layer "F.Cu")
		(net "M_C_CPU1_SB_DQ<24>")
	)
	(segment
		(start 29.402786 -204.116686)
		(end 30.771846 -204.116686)
		(width 0.20066)
		(layer "F.Cu")
		(net "M_C_CPU1_SB_DQ<24>")
	)
	(segment
		(start 26.212038 -203.691744)
		(end 26.459942 -203.691744)
		(width 0.101854)
		(layer "F.Cu")
		(net "M_C_CPU1_SB_DQ<24>")
	)
	(segment
		(start 95.663766 -229.808532)
		(end 95.663766 -229.272846)
		(width 0.20066)
		(layer "F.Cu")
		(net "M_C_CPU1_SB_DQ<24>")
	)
	(segment
		(start 25.259792 -204.355446)
		(end 25.432512 -204.182726)
		(width 0.20066)
		(layer "F.Cu")
		(net "M_C_CPU1_SB_DQ<24>")
	)
	(segment
		(start 28.977844 -203.691744)
		(end 29.402786 -204.116686)
		(width 0.20066)
		(layer "F.Cu")
		(net "M_C_CPU1_SB_DQ<24>")
	)
	(segment
		(start 25.432512 -203.893166)
		(end 25.642062 -203.683616)
		(width 0.20066)
		(layer "F.Cu")
		(net "M_C_CPU1_SB_DQ<24>")
	)
	(segment
		(start 25.642062 -203.683616)
		(end 26.20391 -203.683616)
		(width 0.20066)
		(layer "F.Cu")
		(net "M_C_CPU1_SB_DQ<24>")
	)
	(segment
		(start 24.801068 -204.355446)
		(end 25.259792 -204.355446)
		(width 0.20066)
		(layer "F.Cu")
		(net "M_C_CPU1_SB_DQ<24>")
	)
	(segment
		(start 37.977572 -202.417426)
		(end 36.712906 -202.417426)
		(width 0.18288)
		(layer "In6.Cu")
		(net "M_C_CPU1_SB_DQ<24>")
	)
	(segment
		(start 46.689264 -202.84186)
		(end 46.004226 -202.156822)
		(width 0.18288)
		(layer "In6.Cu")
		(net "M_C_CPU1_SB_DQ<24>")
	)
	(segment
		(start 83.880706 -226.385882)
		(end 83.880706 -226.07778)
		(width 0.088646)
		(layer "In6.Cu")
		(net "M_C_CPU1_SB_DQ<24>")
	)
	(segment
		(start 48.021494 -201.991722)
		(end 47.171356 -202.84186)
		(width 0.18288)
		(layer "In6.Cu")
		(net "M_C_CPU1_SB_DQ<24>")
	)
	(segment
		(start 38.314884 -202.080114)
		(end 37.977572 -202.417426)
		(width 0.18288)
		(layer "In6.Cu")
		(net "M_C_CPU1_SB_DQ<24>")
	)
	(segment
		(start 52.649882 -201.991722)
		(end 52.297838 -202.343766)
		(width 0.18288)
		(layer "In6.Cu")
		(net "M_C_CPU1_SB_DQ<24>")
	)
	(segment
		(start 53.684678 -202.343766)
		(end 53.343302 -202.343766)
		(width 0.18288)
		(layer "In6.Cu")
		(net "M_C_CPU1_SB_DQ<24>")
	)
	(segment
		(start 62.68593 -203.96073)
		(end 59.89193 -203.96073)
		(width 0.18288)
		(layer "In6.Cu")
		(net "M_C_CPU1_SB_DQ<24>")
	)
	(segment
		(start 33.34004 -203.635864)
		(end 33.15716 -203.452984)
		(width 0.18288)
		(layer "In6.Cu")
		(net "M_C_CPU1_SB_DQ<24>")
	)
	(segment
		(start 50.5333 -201.991722)
		(end 50.22469 -201.683112)
		(width 0.18288)
		(layer "In6.Cu")
		(net "M_C_CPU1_SB_DQ<24>")
	)
	(segment
		(start 33.15716 -203.023724)
		(end 32.97428 -202.840844)
		(width 0.18288)
		(layer "In6.Cu")
		(net "M_C_CPU1_SB_DQ<24>")
	)
	(segment
		(start 50.22469 -201.683112)
		(end 49.83988 -201.683112)
		(width 0.18288)
		(layer "In6.Cu")
		(net "M_C_CPU1_SB_DQ<24>")
	)
	(segment
		(start 36.289488 -202.840844)
		(end 34.03346 -202.840844)
		(width 0.18288)
		(layer "In6.Cu")
		(net "M_C_CPU1_SB_DQ<24>")
	)
	(segment
		(start 41.021762 -201.884026)
		(end 40.825674 -202.080114)
		(width 0.18288)
		(layer "In6.Cu")
		(net "M_C_CPU1_SB_DQ<24>")
	)
	(segment
		(start 44.340526 -201.884026)
		(end 41.021762 -201.884026)
		(width 0.18288)
		(layer "In6.Cu")
		(net "M_C_CPU1_SB_DQ<24>")
	)
	(segment
		(start 79.719424 -224.913444)
		(end 78.405482 -223.599502)
		(width 0.18288)
		(layer "In6.Cu")
		(net "M_C_CPU1_SB_DQ<24>")
	)
	(segment
		(start 87.488268 -228.783388)
		(end 87.479378 -228.778308)
		(width 0.088646)
		(layer "In6.Cu")
		(net "M_C_CPU1_SB_DQ<24>")
	)
	(segment
		(start 63.504826 -204.779626)
		(end 62.68593 -203.96073)
		(width 0.18288)
		(layer "In6.Cu")
		(net "M_C_CPU1_SB_DQ<24>")
	)
	(segment
		(start 84.59089 -227.096066)
		(end 83.880706 -226.385882)
		(width 0.088646)
		(layer "In6.Cu")
		(net "M_C_CPU1_SB_DQ<24>")
	)
	(segment
		(start 40.825674 -202.080114)
		(end 38.314884 -202.080114)
		(width 0.18288)
		(layer "In6.Cu")
		(net "M_C_CPU1_SB_DQ<24>")
	)
	(segment
		(start 92.106496 -229.588568)
		(end 92.091764 -229.597204)
		(width 0.088646)
		(layer "In6.Cu")
		(net "M_C_CPU1_SB_DQ<24>")
	)
	(segment
		(start 82.479642 -224.913444)
		(end 79.719424 -224.913444)
		(width 0.18288)
		(layer "In6.Cu")
		(net "M_C_CPU1_SB_DQ<24>")
	)
	(segment
		(start 52.991258 -201.991722)
		(end 52.649882 -201.991722)
		(width 0.18288)
		(layer "In6.Cu")
		(net "M_C_CPU1_SB_DQ<24>")
	)
	(segment
		(start 85.053424 -227.149406)
		(end 85.04301 -227.155502)
		(width 0.088646)
		(layer "In6.Cu")
		(net "M_C_CPU1_SB_DQ<24>")
	)
	(segment
		(start 86.830916 -227.660454)
		(end 86.830916 -227.64496)
		(width 0.088646)
		(layer "In6.Cu")
		(net "M_C_CPU1_SB_DQ<24>")
	)
	(segment
		(start 91.529916 -229.272846)
		(end 91.529916 -229.26294)
		(width 0.088646)
		(layer "In6.Cu")
		(net "M_C_CPU1_SB_DQ<24>")
	)
	(segment
		(start 32.3977 -203.595732)
		(end 31.876746 -204.116686)
		(width 0.18288)
		(layer "In6.Cu")
		(net "M_C_CPU1_SB_DQ<24>")
	)
	(segment
		(start 66.086736 -206.487268)
		(end 64.379094 -204.779626)
		(width 0.18288)
		(layer "In6.Cu")
		(net "M_C_CPU1_SB_DQ<24>")
	)
	(segment
		(start 33.6677 -203.635864)
		(end 33.34004 -203.635864)
		(width 0.18288)
		(layer "In6.Cu")
		(net "M_C_CPU1_SB_DQ<24>")
	)
	(segment
		(start 66.747136 -206.487268)
		(end 66.086736 -206.487268)
		(width 0.18288)
		(layer "In6.Cu")
		(net "M_C_CPU1_SB_DQ<24>")
	)
	(segment
		(start 94.921324 -229.591108)
		(end 94.91091 -229.597204)
		(width 0.088646)
		(layer "In6.Cu")
		(net "M_C_CPU1_SB_DQ<24>")
	)
	(segment
		(start 49.53127 -201.991722)
		(end 48.021494 -201.991722)
		(width 0.18288)
		(layer "In6.Cu")
		(net "M_C_CPU1_SB_DQ<24>")
	)
	(segment
		(start 78.405482 -223.599502)
		(end 78.405482 -220.809312)
		(width 0.18288)
		(layer "In6.Cu")
		(net "M_C_CPU1_SB_DQ<24>")
	)
	(segment
		(start 32.97428 -202.840844)
		(end 32.582104 -202.840844)
		(width 0.18288)
		(layer "In6.Cu")
		(net "M_C_CPU1_SB_DQ<24>")
	)
	(segment
		(start 78.405482 -220.809312)
		(end 70.003416 -212.407246)
		(width 0.18288)
		(layer "In6.Cu")
		(net "M_C_CPU1_SB_DQ<24>")
	)
	(segment
		(start 70.003416 -212.407246)
		(end 68.12026 -207.860392)
		(width 0.18288)
		(layer "In6.Cu")
		(net "M_C_CPU1_SB_DQ<24>")
	)
	(segment
		(start 88.427814 -228.783388)
		(end 88.4174 -228.777292)
		(width 0.088646)
		(layer "In6.Cu")
		(net "M_C_CPU1_SB_DQ<24>")
	)
	(segment
		(start 36.712906 -202.417426)
		(end 36.289488 -202.840844)
		(width 0.18288)
		(layer "In6.Cu")
		(net "M_C_CPU1_SB_DQ<24>")
	)
	(segment
		(start 86.548214 -227.155502)
		(end 86.5378 -227.149406)
		(width 0.088646)
		(layer "In6.Cu")
		(net "M_C_CPU1_SB_DQ<24>")
	)
	(segment
		(start 47.171356 -202.84186)
		(end 46.689264 -202.84186)
		(width 0.18288)
		(layer "In6.Cu")
		(net "M_C_CPU1_SB_DQ<24>")
	)
	(segment
		(start 90.307414 -228.783388)
		(end 90.292682 -228.774752)
		(width 0.088646)
		(layer "In6.Cu")
		(net "M_C_CPU1_SB_DQ<24>")
	)
	(segment
		(start 51.956462 -202.343766)
		(end 51.604418 -201.991722)
		(width 0.18288)
		(layer "In6.Cu")
		(net "M_C_CPU1_SB_DQ<24>")
	)
	(segment
		(start 64.379094 -204.779626)
		(end 63.504826 -204.779626)
		(width 0.18288)
		(layer "In6.Cu")
		(net "M_C_CPU1_SB_DQ<24>")
	)
	(segment
		(start 87.300816 -228.45903)
		(end 87.300562 -228.444806)
		(width 0.088646)
		(layer "In6.Cu")
		(net "M_C_CPU1_SB_DQ<24>")
	)
	(segment
		(start 33.15716 -203.452984)
		(end 33.15716 -203.023724)
		(width 0.18288)
		(layer "In6.Cu")
		(net "M_C_CPU1_SB_DQ<24>")
	)
	(segment
		(start 34.03346 -202.840844)
		(end 33.85058 -203.023724)
		(width 0.18288)
		(layer "In6.Cu")
		(net "M_C_CPU1_SB_DQ<24>")
	)
	(segment
		(start 54.036722 -201.991722)
		(end 53.684678 -202.343766)
		(width 0.18288)
		(layer "In6.Cu")
		(net "M_C_CPU1_SB_DQ<24>")
	)
	(segment
		(start 54.874922 -201.991722)
		(end 54.036722 -201.991722)
		(width 0.18288)
		(layer "In6.Cu")
		(net "M_C_CPU1_SB_DQ<24>")
	)
	(segment
		(start 52.297838 -202.343766)
		(end 51.956462 -202.343766)
		(width 0.18288)
		(layer "In6.Cu")
		(net "M_C_CPU1_SB_DQ<24>")
	)
	(segment
		(start 93.046296 -229.588568)
		(end 93.031564 -229.597204)
		(width 0.088646)
		(layer "In6.Cu")
		(net "M_C_CPU1_SB_DQ<24>")
	)
	(segment
		(start 51.604418 -201.991722)
		(end 50.5333 -201.991722)
		(width 0.18288)
		(layer "In6.Cu")
		(net "M_C_CPU1_SB_DQ<24>")
	)
	(segment
		(start 49.83988 -201.683112)
		(end 49.53127 -201.991722)
		(width 0.18288)
		(layer "In6.Cu")
		(net "M_C_CPU1_SB_DQ<24>")
	)
	(segment
		(start 91.717368 -229.597204)
		(end 91.708478 -229.592124)
		(width 0.088646)
		(layer "In6.Cu")
		(net "M_C_CPU1_SB_DQ<24>")
	)
	(segment
		(start 53.343302 -202.343766)
		(end 52.991258 -201.991722)
		(width 0.18288)
		(layer "In6.Cu")
		(net "M_C_CPU1_SB_DQ<24>")
	)
	(segment
		(start 84.67725 -227.160328)
		(end 84.668868 -227.155502)
		(width 0.088646)
		(layer "In6.Cu")
		(net "M_C_CPU1_SB_DQ<24>")
	)
	(segment
		(start 86.55431 -227.159058)
		(end 86.548214 -227.155502)
		(width 0.088646)
		(layer "In6.Cu")
		(net "M_C_CPU1_SB_DQ<24>")
	)
	(segment
		(start 91.247468 -228.783388)
		(end 91.237054 -228.777292)
		(width 0.088646)
		(layer "In6.Cu")
		(net "M_C_CPU1_SB_DQ<24>")
	)
	(segment
		(start 32.582104 -202.840844)
		(end 32.3977 -203.025248)
		(width 0.18288)
		(layer "In6.Cu")
		(net "M_C_CPU1_SB_DQ<24>")
	)
	(segment
		(start 32.3977 -203.025248)
		(end 32.3977 -203.595732)
		(width 0.18288)
		(layer "In6.Cu")
		(net "M_C_CPU1_SB_DQ<24>")
	)
	(segment
		(start 33.85058 -203.452984)
		(end 33.6677 -203.635864)
		(width 0.18288)
		(layer "In6.Cu")
		(net "M_C_CPU1_SB_DQ<24>")
	)
	(segment
		(start 33.85058 -203.023724)
		(end 33.85058 -203.452984)
		(width 0.18288)
		(layer "In6.Cu")
		(net "M_C_CPU1_SB_DQ<24>")
	)
	(segment
		(start 59.034426 -203.103226)
		(end 55.986426 -203.103226)
		(width 0.18288)
		(layer "In6.Cu")
		(net "M_C_CPU1_SB_DQ<24>")
	)
	(segment
		(start 93.981778 -229.591108)
		(end 93.971364 -229.597204)
		(width 0.088646)
		(layer "In6.Cu")
		(net "M_C_CPU1_SB_DQ<24>")
	)
	(segment
		(start 68.12026 -207.860392)
		(end 66.747136 -206.487268)
		(width 0.18288)
		(layer "In6.Cu")
		(net "M_C_CPU1_SB_DQ<24>")
	)
	(segment
		(start 46.004226 -202.156822)
		(end 44.613322 -202.156822)
		(width 0.18288)
		(layer "In6.Cu")
		(net "M_C_CPU1_SB_DQ<24>")
	)
	(segment
		(start 59.89193 -203.96073)
		(end 59.034426 -203.103226)
		(width 0.18288)
		(layer "In6.Cu")
		(net "M_C_CPU1_SB_DQ<24>")
	)
	(segment
		(start 83.880706 -226.07778)
		(end 82.71637 -224.913444)
		(width 0.088646)
		(layer "In6.Cu")
		(net "M_C_CPU1_SB_DQ<24>")
	)
	(segment
		(start 44.613322 -202.156822)
		(end 44.340526 -201.884026)
		(width 0.18288)
		(layer "In6.Cu")
		(net "M_C_CPU1_SB_DQ<24>")
	)
	(segment
		(start 89.367614 -228.783388)
		(end 89.352882 -228.774752)
		(width 0.088646)
		(layer "In6.Cu")
		(net "M_C_CPU1_SB_DQ<24>")
	)
	(segment
		(start 82.71637 -224.913444)
		(end 82.479642 -224.913444)
		(width 0.088646)
		(layer "In6.Cu")
		(net "M_C_CPU1_SB_DQ<24>")
	)
	(segment
		(start 55.986426 -203.103226)
		(end 54.874922 -201.991722)
		(width 0.18288)
		(layer "In6.Cu")
		(net "M_C_CPU1_SB_DQ<24>")
	)
	(arc
		(start 85.04301 -227.155502)
		(mid 84.860759 -227.205613)
		(end 84.67725 -227.160328)
		(width 0.088646)
		(layer "In6.Cu")
		(net "M_C_CPU1_SB_DQ<24>")
	)
	(arc
		(start 91.708478 -229.592124)
		(mid 91.577564 -229.455764)
		(end 91.529916 -229.272846)
		(width 0.088646)
		(layer "In6.Cu")
		(net "M_C_CPU1_SB_DQ<24>")
	)
	(arc
		(start 87.300562 -228.444806)
		(mid 87.221431 -228.17027)
		(end 87.018114 -227.969572)
		(width 0.088646)
		(layer "In6.Cu")
		(net "M_C_CPU1_SB_DQ<24>")
	)
	(arc
		(start 93.596968 -229.597204)
		(mid 93.322769 -229.521369)
		(end 93.046296 -229.588568)
		(width 0.088646)
		(layer "In6.Cu")
		(net "M_C_CPU1_SB_DQ<24>")
	)
	(arc
		(start 88.4174 -228.777292)
		(mid 88.139222 -228.707569)
		(end 87.862664 -228.783388)
		(width 0.088646)
		(layer "In6.Cu")
		(net "M_C_CPU1_SB_DQ<24>")
	)
	(arc
		(start 91.237054 -228.777292)
		(mid 90.958622 -228.707446)
		(end 90.68181 -228.783388)
		(width 0.088646)
		(layer "In6.Cu")
		(net "M_C_CPU1_SB_DQ<24>")
	)
	(arc
		(start 85.608668 -227.155502)
		(mid 85.331855 -227.079632)
		(end 85.053424 -227.149406)
		(width 0.088646)
		(layer "In6.Cu")
		(net "M_C_CPU1_SB_DQ<24>")
	)
	(arc
		(start 88.80221 -228.783388)
		(mid 88.615012 -228.833531)
		(end 88.427814 -228.783388)
		(width 0.088646)
		(layer "In6.Cu")
		(net "M_C_CPU1_SB_DQ<24>")
	)
	(arc
		(start 87.862664 -228.783388)
		(mid 87.675466 -228.833531)
		(end 87.488268 -228.783388)
		(width 0.088646)
		(layer "In6.Cu")
		(net "M_C_CPU1_SB_DQ<24>")
	)
	(arc
		(start 92.091764 -229.597204)
		(mid 91.904566 -229.647347)
		(end 91.717368 -229.597204)
		(width 0.088646)
		(layer "In6.Cu")
		(net "M_C_CPU1_SB_DQ<24>")
	)
	(arc
		(start 90.68181 -228.783388)
		(mid 90.494612 -228.833531)
		(end 90.307414 -228.783388)
		(width 0.088646)
		(layer "In6.Cu")
		(net "M_C_CPU1_SB_DQ<24>")
	)
	(arc
		(start 95.663766 -229.272846)
		(mid 95.282617 -229.408818)
		(end 94.921324 -229.591108)
		(width 0.088646)
		(layer "In6.Cu")
		(net "M_C_CPU1_SB_DQ<24>")
	)
	(arc
		(start 94.91091 -229.597204)
		(mid 94.723712 -229.647347)
		(end 94.536514 -229.597204)
		(width 0.088646)
		(layer "In6.Cu")
		(net "M_C_CPU1_SB_DQ<24>")
	)
	(arc
		(start 87.018114 -227.969572)
		(mid 86.884786 -227.839072)
		(end 86.830916 -227.660454)
		(width 0.088646)
		(layer "In6.Cu")
		(net "M_C_CPU1_SB_DQ<24>")
	)
	(arc
		(start 89.74201 -228.783388)
		(mid 89.554812 -228.833531)
		(end 89.367614 -228.783388)
		(width 0.088646)
		(layer "In6.Cu")
		(net "M_C_CPU1_SB_DQ<24>")
	)
	(arc
		(start 89.352882 -228.774752)
		(mid 89.076407 -228.707432)
		(end 88.80221 -228.783388)
		(width 0.088646)
		(layer "In6.Cu")
		(net "M_C_CPU1_SB_DQ<24>")
	)
	(arc
		(start 84.668868 -227.155502)
		(mid 84.627939 -227.128331)
		(end 84.59089 -227.096066)
		(width 0.088646)
		(layer "In6.Cu")
		(net "M_C_CPU1_SB_DQ<24>")
	)
	(arc
		(start 93.971364 -229.597204)
		(mid 93.784166 -229.647347)
		(end 93.596968 -229.597204)
		(width 0.088646)
		(layer "In6.Cu")
		(net "M_C_CPU1_SB_DQ<24>")
	)
	(arc
		(start 92.657168 -229.597204)
		(mid 92.382969 -229.521369)
		(end 92.106496 -229.588568)
		(width 0.088646)
		(layer "In6.Cu")
		(net "M_C_CPU1_SB_DQ<24>")
	)
	(arc
		(start 93.031564 -229.597204)
		(mid 92.844366 -229.647347)
		(end 92.657168 -229.597204)
		(width 0.088646)
		(layer "In6.Cu")
		(net "M_C_CPU1_SB_DQ<24>")
	)
	(arc
		(start 90.292682 -228.774752)
		(mid 90.016207 -228.707432)
		(end 89.74201 -228.783388)
		(width 0.088646)
		(layer "In6.Cu")
		(net "M_C_CPU1_SB_DQ<24>")
	)
	(arc
		(start 85.983064 -227.155502)
		(mid 85.795866 -227.205645)
		(end 85.608668 -227.155502)
		(width 0.088646)
		(layer "In6.Cu")
		(net "M_C_CPU1_SB_DQ<24>")
	)
	(arc
		(start 87.479378 -228.778308)
		(mid 87.348464 -228.641948)
		(end 87.300816 -228.45903)
		(width 0.088646)
		(layer "In6.Cu")
		(net "M_C_CPU1_SB_DQ<24>")
	)
	(arc
		(start 91.529916 -229.26294)
		(mid 91.451805 -228.985991)
		(end 91.247468 -228.783388)
		(width 0.088646)
		(layer "In6.Cu")
		(net "M_C_CPU1_SB_DQ<24>")
	)
	(arc
		(start 86.5378 -227.149406)
		(mid 86.259622 -227.079683)
		(end 85.983064 -227.155502)
		(width 0.088646)
		(layer "In6.Cu")
		(net "M_C_CPU1_SB_DQ<24>")
	)
	(arc
		(start 86.830916 -227.64496)
		(mid 86.756925 -227.365394)
		(end 86.55431 -227.159058)
		(width 0.088646)
		(layer "In6.Cu")
		(net "M_C_CPU1_SB_DQ<24>")
	)
	(arc
		(start 94.536514 -229.597204)
		(mid 94.259955 -229.521461)
		(end 93.981778 -229.591108)
		(width 0.088646)
		(layer "In6.Cu")
		(net "M_C_CPU1_SB_DQ<24>")
	)
	(segment
		(start 35.976814 -204.96657)
		(end 34.871914 -204.96657)
		(width 0.20066)
		(layer "F.Cu")
		(net "M_C_CPU1_SB_DQ<23>")
	)
	(segment
		(start 29.29382 -205.405736)
		(end 29.647642 -205.405736)
		(width 0.20066)
		(layer "F.Cu")
		(net "M_C_CPU1_SB_DQ<23>")
	)
	(segment
		(start 32.666178 -205.242414)
		(end 32.666178 -205.090776)
		(width 0.20066)
		(layer "F.Cu")
		(net "M_C_CPU1_SB_DQ<23>")
	)
	(segment
		(start 32.51708 -205.391512)
		(end 32.666178 -205.242414)
		(width 0.20066)
		(layer "F.Cu")
		(net "M_C_CPU1_SB_DQ<23>")
	)
	(segment
		(start 29.151326 -205.092554)
		(end 29.151326 -205.263242)
		(width 0.20066)
		(layer "F.Cu")
		(net "M_C_CPU1_SB_DQ<23>")
	)
	(segment
		(start 29.661866 -205.391512)
		(end 29.899864 -205.391512)
		(width 0.101854)
		(layer "F.Cu")
		(net "M_C_CPU1_SB_DQ<23>")
	)
	(segment
		(start 33.401762 -205.174088)
		(end 33.848294 -205.174088)
		(width 0.20066)
		(layer "F.Cu")
		(net "M_C_CPU1_SB_DQ<23>")
	)
	(segment
		(start 27.328114 -204.96657)
		(end 29.025342 -204.96657)
		(width 0.20066)
		(layer "F.Cu")
		(net "M_C_CPU1_SB_DQ<23>")
	)
	(segment
		(start 29.025342 -204.96657)
		(end 29.151326 -205.092554)
		(width 0.20066)
		(layer "F.Cu")
		(net "M_C_CPU1_SB_DQ<23>")
	)
	(segment
		(start 34.055812 -204.96657)
		(end 34.871914 -204.96657)
		(width 0.20066)
		(layer "F.Cu")
		(net "M_C_CPU1_SB_DQ<23>")
	)
	(segment
		(start 29.899864 -205.391512)
		(end 31.972758 -205.391512)
		(width 0.1016)
		(layer "F.Cu")
		(net "M_C_CPU1_SB_DQ<23>")
	)
	(segment
		(start 29.647642 -205.405736)
		(end 29.661866 -205.391512)
		(width 0.101854)
		(layer "F.Cu")
		(net "M_C_CPU1_SB_DQ<23>")
	)
	(segment
		(start 32.666178 -205.090776)
		(end 32.794702 -204.962252)
		(width 0.20066)
		(layer "F.Cu")
		(net "M_C_CPU1_SB_DQ<23>")
	)
	(segment
		(start 93.314266 -228.99497)
		(end 93.314012 -228.994716)
		(width 0.20066)
		(layer "F.Cu")
		(net "M_C_CPU1_SB_DQ<23>")
	)
	(segment
		(start 29.151326 -205.263242)
		(end 29.29382 -205.405736)
		(width 0.20066)
		(layer "F.Cu")
		(net "M_C_CPU1_SB_DQ<23>")
	)
	(segment
		(start 33.189926 -204.962252)
		(end 33.401762 -205.174088)
		(width 0.20066)
		(layer "F.Cu")
		(net "M_C_CPU1_SB_DQ<23>")
	)
	(segment
		(start 33.848294 -205.174088)
		(end 34.055812 -204.96657)
		(width 0.20066)
		(layer "F.Cu")
		(net "M_C_CPU1_SB_DQ<23>")
	)
	(segment
		(start 93.314012 -228.994716)
		(end 93.314012 -228.45903)
		(width 0.20066)
		(layer "F.Cu")
		(net "M_C_CPU1_SB_DQ<23>")
	)
	(segment
		(start 31.972758 -205.391512)
		(end 32.51708 -205.391512)
		(width 0.20066)
		(layer "F.Cu")
		(net "M_C_CPU1_SB_DQ<23>")
	)
	(segment
		(start 32.794702 -204.962252)
		(end 33.189926 -204.962252)
		(width 0.20066)
		(layer "F.Cu")
		(net "M_C_CPU1_SB_DQ<23>")
	)
	(segment
		(start 38.069774 -205.410816)
		(end 37.886894 -205.593696)
		(width 0.18288)
		(layer "In4.Cu")
		(net "M_C_CPU1_SB_DQ<23>")
	)
	(segment
		(start 50.969418 -205.391258)
		(end 50.68062 -205.510892)
		(width 0.18288)
		(layer "In4.Cu")
		(net "M_C_CPU1_SB_DQ<23>")
	)
	(segment
		(start 36.415472 -204.786738)
		(end 36.156646 -204.786738)
		(width 0.18288)
		(layer "In4.Cu")
		(net "M_C_CPU1_SB_DQ<23>")
	)
	(segment
		(start 46.441614 -206.241904)
		(end 46.120812 -205.921102)
		(width 0.18288)
		(layer "In4.Cu")
		(net "M_C_CPU1_SB_DQ<23>")
	)
	(segment
		(start 84.319618 -227.975414)
		(end 83.937348 -227.593144)
		(width 0.088646)
		(layer "In4.Cu")
		(net "M_C_CPU1_SB_DQ<23>")
	)
	(segment
		(start 91.717114 -227.969318)
		(end 91.7067 -227.963222)
		(width 0.088646)
		(layer "In4.Cu")
		(net "M_C_CPU1_SB_DQ<23>")
	)
	(segment
		(start 87.018114 -227.969318)
		(end 87.0077 -227.963222)
		(width 0.088646)
		(layer "In4.Cu")
		(net "M_C_CPU1_SB_DQ<23>")
	)
	(segment
		(start 82.708496 -226.361752)
		(end 78.985872 -226.361752)
		(width 0.18288)
		(layer "In4.Cu")
		(net "M_C_CPU1_SB_DQ<23>")
	)
	(segment
		(start 38.760654 -205.410816)
		(end 38.760654 -203.897738)
		(width 0.18288)
		(layer "In4.Cu")
		(net "M_C_CPU1_SB_DQ<23>")
	)
	(segment
		(start 44.82846 -205.921102)
		(end 44.139866 -205.232508)
		(width 0.18288)
		(layer "In4.Cu")
		(net "M_C_CPU1_SB_DQ<23>")
	)
	(segment
		(start 38.252654 -203.714858)
		(end 38.069774 -203.897738)
		(width 0.18288)
		(layer "In4.Cu")
		(net "M_C_CPU1_SB_DQ<23>")
	)
	(segment
		(start 93.001084 -228.45903)
		(end 92.93606 -228.394006)
		(width 0.088646)
		(layer "In4.Cu")
		(net "M_C_CPU1_SB_DQ<23>")
	)
	(segment
		(start 50.68062 -205.510892)
		(end 50.454306 -205.737206)
		(width 0.18288)
		(layer "In4.Cu")
		(net "M_C_CPU1_SB_DQ<23>")
	)
	(segment
		(start 38.069774 -203.897738)
		(end 38.069774 -205.410816)
		(width 0.18288)
		(layer "In4.Cu")
		(net "M_C_CPU1_SB_DQ<23>")
	)
	(segment
		(start 82.940906 -226.361752)
		(end 82.708496 -226.361752)
		(width 0.088646)
		(layer "In4.Cu")
		(net "M_C_CPU1_SB_DQ<23>")
	)
	(segment
		(start 44.139866 -205.232508)
		(end 40.357298 -205.232508)
		(width 0.18288)
		(layer "In4.Cu")
		(net "M_C_CPU1_SB_DQ<23>")
	)
	(segment
		(start 86.078568 -227.969318)
		(end 86.068154 -227.963222)
		(width 0.088646)
		(layer "In4.Cu")
		(net "M_C_CPU1_SB_DQ<23>")
	)
	(segment
		(start 38.577774 -203.714858)
		(end 38.252654 -203.714858)
		(width 0.18288)
		(layer "In4.Cu")
		(net "M_C_CPU1_SB_DQ<23>")
	)
	(segment
		(start 63.277242 -206.101696)
		(end 59.13374 -206.101696)
		(width 0.18288)
		(layer "In4.Cu")
		(net "M_C_CPU1_SB_DQ<23>")
	)
	(segment
		(start 68.351908 -208.646776)
		(end 66.26733 -206.562198)
		(width 0.18288)
		(layer "In4.Cu")
		(net "M_C_CPU1_SB_DQ<23>")
	)
	(segment
		(start 83.937348 -227.358194)
		(end 82.940906 -226.361752)
		(width 0.088646)
		(layer "In4.Cu")
		(net "M_C_CPU1_SB_DQ<23>")
	)
	(segment
		(start 55.028084 -205.706726)
		(end 51.777392 -205.706726)
		(width 0.18288)
		(layer "In4.Cu")
		(net "M_C_CPU1_SB_DQ<23>")
	)
	(segment
		(start 88.347296 -227.960682)
		(end 88.332564 -227.969318)
		(width 0.088646)
		(layer "In4.Cu")
		(net "M_C_CPU1_SB_DQ<23>")
	)
	(segment
		(start 50.454306 -205.737206)
		(end 50.168048 -205.737206)
		(width 0.18288)
		(layer "In4.Cu")
		(net "M_C_CPU1_SB_DQ<23>")
	)
	(segment
		(start 92.101924 -227.963222)
		(end 92.09151 -227.969318)
		(width 0.088646)
		(layer "In4.Cu")
		(net "M_C_CPU1_SB_DQ<23>")
	)
	(segment
		(start 40.357298 -205.232508)
		(end 39.99611 -205.593696)
		(width 0.18288)
		(layer "In4.Cu")
		(net "M_C_CPU1_SB_DQ<23>")
	)
	(segment
		(start 59.13374 -206.101696)
		(end 58.862722 -206.372714)
		(width 0.18288)
		(layer "In4.Cu")
		(net "M_C_CPU1_SB_DQ<23>")
	)
	(segment
		(start 87.958168 -227.969318)
		(end 87.947754 -227.963222)
		(width 0.088646)
		(layer "In4.Cu")
		(net "M_C_CPU1_SB_DQ<23>")
	)
	(segment
		(start 78.985872 -226.361752)
		(end 73.359264 -220.735144)
		(width 0.18288)
		(layer "In4.Cu")
		(net "M_C_CPU1_SB_DQ<23>")
	)
	(segment
		(start 90.226896 -227.960682)
		(end 90.212164 -227.969318)
		(width 0.088646)
		(layer "In4.Cu")
		(net "M_C_CPU1_SB_DQ<23>")
	)
	(segment
		(start 73.359264 -220.735144)
		(end 68.351908 -208.646776)
		(width 0.18288)
		(layer "In4.Cu")
		(net "M_C_CPU1_SB_DQ<23>")
	)
	(segment
		(start 93.314012 -228.45903)
		(end 93.001084 -228.45903)
		(width 0.088646)
		(layer "In4.Cu")
		(net "M_C_CPU1_SB_DQ<23>")
	)
	(segment
		(start 89.287096 -227.960682)
		(end 89.272364 -227.969318)
		(width 0.088646)
		(layer "In4.Cu")
		(net "M_C_CPU1_SB_DQ<23>")
	)
	(segment
		(start 83.937348 -227.593144)
		(end 83.937348 -227.358194)
		(width 0.088646)
		(layer "In4.Cu")
		(net "M_C_CPU1_SB_DQ<23>")
	)
	(segment
		(start 37.22243 -205.593696)
		(end 36.415472 -204.786738)
		(width 0.18288)
		(layer "In4.Cu")
		(net "M_C_CPU1_SB_DQ<23>")
	)
	(segment
		(start 58.862722 -206.372714)
		(end 55.694072 -206.372714)
		(width 0.18288)
		(layer "In4.Cu")
		(net "M_C_CPU1_SB_DQ<23>")
	)
	(segment
		(start 38.760654 -203.897738)
		(end 38.577774 -203.714858)
		(width 0.18288)
		(layer "In4.Cu")
		(net "M_C_CPU1_SB_DQ<23>")
	)
	(segment
		(start 51.777392 -205.706726)
		(end 51.461924 -205.391258)
		(width 0.18288)
		(layer "In4.Cu")
		(net "M_C_CPU1_SB_DQ<23>")
	)
	(segment
		(start 38.943534 -205.593696)
		(end 38.760654 -205.410816)
		(width 0.18288)
		(layer "In4.Cu")
		(net "M_C_CPU1_SB_DQ<23>")
	)
	(segment
		(start 84.58327 -227.975414)
		(end 84.319618 -227.975414)
		(width 0.088646)
		(layer "In4.Cu")
		(net "M_C_CPU1_SB_DQ<23>")
	)
	(segment
		(start 49.66335 -206.241904)
		(end 46.441614 -206.241904)
		(width 0.18288)
		(layer "In4.Cu")
		(net "M_C_CPU1_SB_DQ<23>")
	)
	(segment
		(start 55.694072 -206.372714)
		(end 55.028084 -205.706726)
		(width 0.18288)
		(layer "In4.Cu")
		(net "M_C_CPU1_SB_DQ<23>")
	)
	(segment
		(start 51.461924 -205.391258)
		(end 50.969418 -205.391258)
		(width 0.18288)
		(layer "In4.Cu")
		(net "M_C_CPU1_SB_DQ<23>")
	)
	(segment
		(start 50.168048 -205.737206)
		(end 49.66335 -206.241904)
		(width 0.18288)
		(layer "In4.Cu")
		(net "M_C_CPU1_SB_DQ<23>")
	)
	(segment
		(start 63.737744 -206.562198)
		(end 63.277242 -206.101696)
		(width 0.18288)
		(layer "In4.Cu")
		(net "M_C_CPU1_SB_DQ<23>")
	)
	(segment
		(start 66.26733 -206.562198)
		(end 63.737744 -206.562198)
		(width 0.18288)
		(layer "In4.Cu")
		(net "M_C_CPU1_SB_DQ<23>")
	)
	(segment
		(start 39.99611 -205.593696)
		(end 38.943534 -205.593696)
		(width 0.18288)
		(layer "In4.Cu")
		(net "M_C_CPU1_SB_DQ<23>")
	)
	(segment
		(start 36.156646 -204.786738)
		(end 35.976814 -204.96657)
		(width 0.18288)
		(layer "In4.Cu")
		(net "M_C_CPU1_SB_DQ<23>")
	)
	(segment
		(start 46.120812 -205.921102)
		(end 44.82846 -205.921102)
		(width 0.18288)
		(layer "In4.Cu")
		(net "M_C_CPU1_SB_DQ<23>")
	)
	(segment
		(start 37.886894 -205.593696)
		(end 37.22243 -205.593696)
		(width 0.18288)
		(layer "In4.Cu")
		(net "M_C_CPU1_SB_DQ<23>")
	)
	(arc
		(start 87.39251 -227.969318)
		(mid 87.205312 -228.019461)
		(end 87.018114 -227.969318)
		(width 0.088646)
		(layer "In4.Cu")
		(net "M_C_CPU1_SB_DQ<23>")
	)
	(arc
		(start 85.138514 -227.969318)
		(mid 84.860082 -227.899504)
		(end 84.58327 -227.975414)
		(width 0.088646)
		(layer "In4.Cu")
		(net "M_C_CPU1_SB_DQ<23>")
	)
	(arc
		(start 87.0077 -227.963222)
		(mid 86.729522 -227.89353)
		(end 86.452964 -227.969318)
		(width 0.088646)
		(layer "In4.Cu")
		(net "M_C_CPU1_SB_DQ<23>")
	)
	(arc
		(start 85.51291 -227.969318)
		(mid 85.325712 -228.019461)
		(end 85.138514 -227.969318)
		(width 0.088646)
		(layer "In4.Cu")
		(net "M_C_CPU1_SB_DQ<23>")
	)
	(arc
		(start 89.837768 -227.969318)
		(mid 89.563539 -227.893393)
		(end 89.287096 -227.960682)
		(width 0.088646)
		(layer "In4.Cu")
		(net "M_C_CPU1_SB_DQ<23>")
	)
	(arc
		(start 92.93606 -228.394006)
		(mid 92.846991 -228.148577)
		(end 92.657168 -227.969318)
		(width 0.088646)
		(layer "In4.Cu")
		(net "M_C_CPU1_SB_DQ<23>")
	)
	(arc
		(start 88.332564 -227.969318)
		(mid 88.145366 -228.019461)
		(end 87.958168 -227.969318)
		(width 0.088646)
		(layer "In4.Cu")
		(net "M_C_CPU1_SB_DQ<23>")
	)
	(arc
		(start 86.452964 -227.969318)
		(mid 86.265766 -228.019461)
		(end 86.078568 -227.969318)
		(width 0.088646)
		(layer "In4.Cu")
		(net "M_C_CPU1_SB_DQ<23>")
	)
	(arc
		(start 91.151964 -227.969318)
		(mid 90.964766 -228.019461)
		(end 90.777568 -227.969318)
		(width 0.088646)
		(layer "In4.Cu")
		(net "M_C_CPU1_SB_DQ<23>")
	)
	(arc
		(start 87.947754 -227.963222)
		(mid 87.669322 -227.893408)
		(end 87.39251 -227.969318)
		(width 0.088646)
		(layer "In4.Cu")
		(net "M_C_CPU1_SB_DQ<23>")
	)
	(arc
		(start 91.7067 -227.963222)
		(mid 91.428522 -227.89353)
		(end 91.151964 -227.969318)
		(width 0.088646)
		(layer "In4.Cu")
		(net "M_C_CPU1_SB_DQ<23>")
	)
	(arc
		(start 88.897968 -227.969318)
		(mid 88.623739 -227.893393)
		(end 88.347296 -227.960682)
		(width 0.088646)
		(layer "In4.Cu")
		(net "M_C_CPU1_SB_DQ<23>")
	)
	(arc
		(start 92.657168 -227.969318)
		(mid 92.380355 -227.893482)
		(end 92.101924 -227.963222)
		(width 0.088646)
		(layer "In4.Cu")
		(net "M_C_CPU1_SB_DQ<23>")
	)
	(arc
		(start 89.272364 -227.969318)
		(mid 89.085166 -228.019461)
		(end 88.897968 -227.969318)
		(width 0.088646)
		(layer "In4.Cu")
		(net "M_C_CPU1_SB_DQ<23>")
	)
	(arc
		(start 90.212164 -227.969318)
		(mid 90.024966 -228.019461)
		(end 89.837768 -227.969318)
		(width 0.088646)
		(layer "In4.Cu")
		(net "M_C_CPU1_SB_DQ<23>")
	)
	(arc
		(start 90.777568 -227.969318)
		(mid 90.503339 -227.893393)
		(end 90.226896 -227.960682)
		(width 0.088646)
		(layer "In4.Cu")
		(net "M_C_CPU1_SB_DQ<23>")
	)
	(arc
		(start 86.068154 -227.963222)
		(mid 85.789722 -227.893408)
		(end 85.51291 -227.969318)
		(width 0.088646)
		(layer "In4.Cu")
		(net "M_C_CPU1_SB_DQ<23>")
	)
	(arc
		(start 92.09151 -227.969318)
		(mid 91.904312 -228.019461)
		(end 91.717114 -227.969318)
		(width 0.088646)
		(layer "In4.Cu")
		(net "M_C_CPU1_SB_DQ<23>")
	)
	(segment
		(start 28.91028 -206.23149)
		(end 29.647642 -206.23149)
		(width 0.20066)
		(layer "F.Cu")
		(net "M_C_CPU1_SB_DQ<22>")
	)
	(segment
		(start 29.657802 -206.24165)
		(end 29.912818 -206.24165)
		(width 0.101854)
		(layer "F.Cu")
		(net "M_C_CPU1_SB_DQ<22>")
	)
	(segment
		(start 93.784166 -229.808532)
		(end 93.784166 -229.272846)
		(width 0.20066)
		(layer "F.Cu")
		(net "M_C_CPU1_SB_DQ<22>")
	)
	(segment
		(start 93.783912 -229.808786)
		(end 93.784166 -229.808532)
		(width 0.20066)
		(layer "F.Cu")
		(net "M_C_CPU1_SB_DQ<22>")
	)
	(segment
		(start 29.647642 -206.23149)
		(end 29.657802 -206.24165)
		(width 0.101854)
		(layer "F.Cu")
		(net "M_C_CPU1_SB_DQ<22>")
	)
	(segment
		(start 29.912818 -206.24165)
		(end 31.972758 -206.24165)
		(width 0.1016)
		(layer "F.Cu")
		(net "M_C_CPU1_SB_DQ<22>")
	)
	(segment
		(start 28.475178 -206.666592)
		(end 28.91028 -206.23149)
		(width 0.20066)
		(layer "F.Cu")
		(net "M_C_CPU1_SB_DQ<22>")
	)
	(segment
		(start 32.74949 -206.711042)
		(end 32.916876 -206.878428)
		(width 0.20066)
		(layer "F.Cu")
		(net "M_C_CPU1_SB_DQ<22>")
	)
	(segment
		(start 32.605726 -206.24165)
		(end 32.74949 -206.385414)
		(width 0.20066)
		(layer "F.Cu")
		(net "M_C_CPU1_SB_DQ<22>")
	)
	(segment
		(start 33.55721 -206.666592)
		(end 34.871914 -206.666592)
		(width 0.20066)
		(layer "F.Cu")
		(net "M_C_CPU1_SB_DQ<22>")
	)
	(segment
		(start 31.972758 -206.24165)
		(end 32.605726 -206.24165)
		(width 0.20066)
		(layer "F.Cu")
		(net "M_C_CPU1_SB_DQ<22>")
	)
	(segment
		(start 32.74949 -206.385414)
		(end 32.74949 -206.711042)
		(width 0.20066)
		(layer "F.Cu")
		(net "M_C_CPU1_SB_DQ<22>")
	)
	(segment
		(start 32.916876 -206.878428)
		(end 33.345374 -206.878428)
		(width 0.20066)
		(layer "F.Cu")
		(net "M_C_CPU1_SB_DQ<22>")
	)
	(segment
		(start 27.328114 -206.666592)
		(end 28.475178 -206.666592)
		(width 0.20066)
		(layer "F.Cu")
		(net "M_C_CPU1_SB_DQ<22>")
	)
	(segment
		(start 33.345374 -206.878428)
		(end 33.55721 -206.666592)
		(width 0.20066)
		(layer "F.Cu")
		(net "M_C_CPU1_SB_DQ<22>")
	)
	(segment
		(start 35.976814 -206.666592)
		(end 34.871914 -206.666592)
		(width 0.20066)
		(layer "F.Cu")
		(net "M_C_CPU1_SB_DQ<22>")
	)
	(segment
		(start 53.81498 -207.274922)
		(end 53.81498 -208.010506)
		(width 0.18288)
		(layer "In4.Cu")
		(net "M_C_CPU1_SB_DQ<22>")
	)
	(segment
		(start 57.416446 -207.423766)
		(end 57.091326 -207.423766)
		(width 0.18288)
		(layer "In4.Cu")
		(net "M_C_CPU1_SB_DQ<22>")
	)
	(segment
		(start 83.921092 -228.783388)
		(end 83.868006 -228.730302)
		(width 0.088646)
		(layer "In4.Cu")
		(net "M_C_CPU1_SB_DQ<22>")
	)
	(segment
		(start 83.868006 -228.185726)
		(end 83.039712 -227.357432)
		(width 0.088646)
		(layer "In4.Cu")
		(net "M_C_CPU1_SB_DQ<22>")
	)
	(segment
		(start 57.599326 -207.606646)
		(end 57.416446 -207.423766)
		(width 0.18288)
		(layer "In4.Cu")
		(net "M_C_CPU1_SB_DQ<22>")
	)
	(segment
		(start 89.742264 -228.783388)
		(end 89.737692 -228.785928)
		(width 0.088646)
		(layer "In4.Cu")
		(net "M_C_CPU1_SB_DQ<22>")
	)
	(segment
		(start 42.090594 -206.979774)
		(end 40.498014 -206.979774)
		(width 0.18288)
		(layer "In4.Cu")
		(net "M_C_CPU1_SB_DQ<22>")
	)
	(segment
		(start 55.844186 -208.11617)
		(end 54.820058 -207.092042)
		(width 0.18288)
		(layer "In4.Cu")
		(net "M_C_CPU1_SB_DQ<22>")
	)
	(segment
		(start 53.324252 -208.193386)
		(end 53.1241 -207.993234)
		(width 0.18288)
		(layer "In4.Cu")
		(net "M_C_CPU1_SB_DQ<22>")
	)
	(segment
		(start 45.378878 -207.941672)
		(end 45.116242 -207.679036)
		(width 0.18288)
		(layer "In4.Cu")
		(net "M_C_CPU1_SB_DQ<22>")
	)
	(segment
		(start 90.68943 -228.77907)
		(end 90.682064 -228.783388)
		(width 0.088646)
		(layer "In4.Cu")
		(net "M_C_CPU1_SB_DQ<22>")
	)
	(segment
		(start 88.802464 -228.783388)
		(end 88.79967 -228.784912)
		(width 0.088646)
		(layer "In4.Cu")
		(net "M_C_CPU1_SB_DQ<22>")
	)
	(segment
		(start 40.498014 -206.979774)
		(end 40.113204 -207.364584)
		(width 0.18288)
		(layer "In4.Cu")
		(net "M_C_CPU1_SB_DQ<22>")
	)
	(segment
		(start 92.561664 -228.783388)
		(end 92.557092 -228.785928)
		(width 0.088646)
		(layer "In4.Cu")
		(net "M_C_CPU1_SB_DQ<22>")
	)
	(segment
		(start 90.682064 -228.783388)
		(end 90.677492 -228.785928)
		(width 0.088646)
		(layer "In4.Cu")
		(net "M_C_CPU1_SB_DQ<22>")
	)
	(segment
		(start 87.488014 -228.783388)
		(end 87.488268 -228.783388)
		(width 0.088646)
		(layer "In4.Cu")
		(net "M_C_CPU1_SB_DQ<22>")
	)
	(segment
		(start 44.135294 -208.046066)
		(end 43.156886 -208.046066)
		(width 0.18288)
		(layer "In4.Cu")
		(net "M_C_CPU1_SB_DQ<22>")
	)
	(segment
		(start 53.81498 -208.010506)
		(end 53.6321 -208.193386)
		(width 0.18288)
		(layer "In4.Cu")
		(net "M_C_CPU1_SB_DQ<22>")
	)
	(segment
		(start 36.674806 -207.364584)
		(end 35.976814 -206.666592)
		(width 0.18288)
		(layer "In4.Cu")
		(net "M_C_CPU1_SB_DQ<22>")
	)
	(segment
		(start 92.56903 -228.77907)
		(end 92.561664 -228.783388)
		(width 0.088646)
		(layer "In4.Cu")
		(net "M_C_CPU1_SB_DQ<22>")
	)
	(segment
		(start 53.99786 -207.092042)
		(end 53.81498 -207.274922)
		(width 0.18288)
		(layer "In4.Cu")
		(net "M_C_CPU1_SB_DQ<22>")
	)
	(segment
		(start 66.594482 -208.911444)
		(end 63.710312 -208.911444)
		(width 0.18288)
		(layer "In4.Cu")
		(net "M_C_CPU1_SB_DQ<22>")
	)
	(segment
		(start 88.80983 -228.77907)
		(end 88.802464 -228.783388)
		(width 0.088646)
		(layer "In4.Cu")
		(net "M_C_CPU1_SB_DQ<22>")
	)
	(segment
		(start 50.541682 -207.092042)
		(end 49.692052 -207.941672)
		(width 0.18288)
		(layer "In4.Cu")
		(net "M_C_CPU1_SB_DQ<22>")
	)
	(segment
		(start 59.409838 -207.89773)
		(end 59.191398 -208.11617)
		(width 0.18288)
		(layer "In4.Cu")
		(net "M_C_CPU1_SB_DQ<22>")
	)
	(segment
		(start 62.696598 -207.89773)
		(end 59.409838 -207.89773)
		(width 0.18288)
		(layer "In4.Cu")
		(net "M_C_CPU1_SB_DQ<22>")
	)
	(segment
		(start 91.62923 -228.77907)
		(end 91.621864 -228.783388)
		(width 0.088646)
		(layer "In4.Cu")
		(net "M_C_CPU1_SB_DQ<22>")
	)
	(segment
		(start 82.708496 -227.357432)
		(end 78.503018 -227.357432)
		(width 0.18288)
		(layer "In4.Cu")
		(net "M_C_CPU1_SB_DQ<22>")
	)
	(segment
		(start 53.1241 -207.993234)
		(end 53.1241 -207.274922)
		(width 0.18288)
		(layer "In4.Cu")
		(net "M_C_CPU1_SB_DQ<22>")
	)
	(segment
		(start 89.74963 -228.77907)
		(end 89.742264 -228.783388)
		(width 0.088646)
		(layer "In4.Cu")
		(net "M_C_CPU1_SB_DQ<22>")
	)
	(segment
		(start 52.94122 -207.092042)
		(end 50.541682 -207.092042)
		(width 0.18288)
		(layer "In4.Cu")
		(net "M_C_CPU1_SB_DQ<22>")
	)
	(segment
		(start 87.862664 -228.783388)
		(end 87.858346 -228.785928)
		(width 0.088646)
		(layer "In4.Cu")
		(net "M_C_CPU1_SB_DQ<22>")
	)
	(segment
		(start 67.940936 -210.257898)
		(end 66.594482 -208.911444)
		(width 0.18288)
		(layer "In4.Cu")
		(net "M_C_CPU1_SB_DQ<22>")
	)
	(segment
		(start 57.599326 -207.93329)
		(end 57.599326 -207.606646)
		(width 0.18288)
		(layer "In4.Cu")
		(net "M_C_CPU1_SB_DQ<22>")
	)
	(segment
		(start 53.6321 -208.193386)
		(end 53.324252 -208.193386)
		(width 0.18288)
		(layer "In4.Cu")
		(net "M_C_CPU1_SB_DQ<22>")
	)
	(segment
		(start 78.503018 -227.357432)
		(end 72.56399 -221.418404)
		(width 0.18288)
		(layer "In4.Cu")
		(net "M_C_CPU1_SB_DQ<22>")
	)
	(segment
		(start 59.191398 -208.11617)
		(end 57.782206 -208.11617)
		(width 0.18288)
		(layer "In4.Cu")
		(net "M_C_CPU1_SB_DQ<22>")
	)
	(segment
		(start 53.1241 -207.274922)
		(end 52.94122 -207.092042)
		(width 0.18288)
		(layer "In4.Cu")
		(net "M_C_CPU1_SB_DQ<22>")
	)
	(segment
		(start 45.116242 -207.679036)
		(end 44.502324 -207.679036)
		(width 0.18288)
		(layer "In4.Cu")
		(net "M_C_CPU1_SB_DQ<22>")
	)
	(segment
		(start 57.091326 -207.423766)
		(end 56.908446 -207.606646)
		(width 0.18288)
		(layer "In4.Cu")
		(net "M_C_CPU1_SB_DQ<22>")
	)
	(segment
		(start 83.039712 -227.357432)
		(end 82.708496 -227.357432)
		(width 0.088646)
		(layer "In4.Cu")
		(net "M_C_CPU1_SB_DQ<22>")
	)
	(segment
		(start 56.908446 -207.93329)
		(end 56.725566 -208.11617)
		(width 0.18288)
		(layer "In4.Cu")
		(net "M_C_CPU1_SB_DQ<22>")
	)
	(segment
		(start 72.56399 -221.418404)
		(end 67.940936 -210.257898)
		(width 0.18288)
		(layer "In4.Cu")
		(net "M_C_CPU1_SB_DQ<22>")
	)
	(segment
		(start 63.710312 -208.911444)
		(end 62.696598 -207.89773)
		(width 0.18288)
		(layer "In4.Cu")
		(net "M_C_CPU1_SB_DQ<22>")
	)
	(segment
		(start 84.103464 -228.783388)
		(end 83.921092 -228.783388)
		(width 0.088646)
		(layer "In4.Cu")
		(net "M_C_CPU1_SB_DQ<22>")
	)
	(segment
		(start 93.203268 -228.82733)
		(end 93.126814 -228.783388)
		(width 0.088646)
		(layer "In4.Cu")
		(net "M_C_CPU1_SB_DQ<22>")
	)
	(segment
		(start 43.156886 -208.046066)
		(end 42.090594 -206.979774)
		(width 0.18288)
		(layer "In4.Cu")
		(net "M_C_CPU1_SB_DQ<22>")
	)
	(segment
		(start 57.782206 -208.11617)
		(end 57.599326 -207.93329)
		(width 0.18288)
		(layer "In4.Cu")
		(net "M_C_CPU1_SB_DQ<22>")
	)
	(segment
		(start 44.502324 -207.679036)
		(end 44.135294 -208.046066)
		(width 0.18288)
		(layer "In4.Cu")
		(net "M_C_CPU1_SB_DQ<22>")
	)
	(segment
		(start 91.621864 -228.783388)
		(end 91.617292 -228.785928)
		(width 0.088646)
		(layer "In4.Cu")
		(net "M_C_CPU1_SB_DQ<22>")
	)
	(segment
		(start 83.868006 -228.730302)
		(end 83.868006 -228.185726)
		(width 0.088646)
		(layer "In4.Cu")
		(net "M_C_CPU1_SB_DQ<22>")
	)
	(segment
		(start 49.692052 -207.941672)
		(end 45.378878 -207.941672)
		(width 0.18288)
		(layer "In4.Cu")
		(net "M_C_CPU1_SB_DQ<22>")
	)
	(segment
		(start 40.113204 -207.364584)
		(end 36.674806 -207.364584)
		(width 0.18288)
		(layer "In4.Cu")
		(net "M_C_CPU1_SB_DQ<22>")
	)
	(segment
		(start 56.725566 -208.11617)
		(end 55.844186 -208.11617)
		(width 0.18288)
		(layer "In4.Cu")
		(net "M_C_CPU1_SB_DQ<22>")
	)
	(segment
		(start 54.820058 -207.092042)
		(end 53.99786 -207.092042)
		(width 0.18288)
		(layer "In4.Cu")
		(net "M_C_CPU1_SB_DQ<22>")
	)
	(segment
		(start 56.908446 -207.606646)
		(end 56.908446 -207.93329)
		(width 0.18288)
		(layer "In4.Cu")
		(net "M_C_CPU1_SB_DQ<22>")
	)
	(arc
		(start 92.557092 -228.785928)
		(mid 92.371707 -228.833598)
		(end 92.187014 -228.783388)
		(width 0.088646)
		(layer "In4.Cu")
		(net "M_C_CPU1_SB_DQ<22>")
	)
	(arc
		(start 89.737692 -228.785928)
		(mid 89.552307 -228.833598)
		(end 89.367614 -228.783388)
		(width 0.088646)
		(layer "In4.Cu")
		(net "M_C_CPU1_SB_DQ<22>")
	)
	(arc
		(start 93.784166 -229.272846)
		(mid 93.508374 -229.030977)
		(end 93.203268 -228.82733)
		(width 0.088646)
		(layer "In4.Cu")
		(net "M_C_CPU1_SB_DQ<22>")
	)
	(arc
		(start 87.488268 -228.783388)
		(mid 87.205566 -228.707612)
		(end 86.922864 -228.783388)
		(width 0.088646)
		(layer "In4.Cu")
		(net "M_C_CPU1_SB_DQ<22>")
	)
	(arc
		(start 93.126814 -228.783388)
		(mid 92.848491 -228.707629)
		(end 92.56903 -228.77907)
		(width 0.088646)
		(layer "In4.Cu")
		(net "M_C_CPU1_SB_DQ<22>")
	)
	(arc
		(start 91.247214 -228.783388)
		(mid 90.968891 -228.707629)
		(end 90.68943 -228.77907)
		(width 0.088646)
		(layer "In4.Cu")
		(net "M_C_CPU1_SB_DQ<22>")
	)
	(arc
		(start 85.043264 -228.783388)
		(mid 84.856066 -228.833531)
		(end 84.668868 -228.783388)
		(width 0.088646)
		(layer "In4.Cu")
		(net "M_C_CPU1_SB_DQ<22>")
	)
	(arc
		(start 86.922864 -228.783388)
		(mid 86.735666 -228.833531)
		(end 86.548468 -228.783388)
		(width 0.088646)
		(layer "In4.Cu")
		(net "M_C_CPU1_SB_DQ<22>")
	)
	(arc
		(start 88.427814 -228.783388)
		(mid 88.145256 -228.707739)
		(end 87.862664 -228.783388)
		(width 0.088646)
		(layer "In4.Cu")
		(net "M_C_CPU1_SB_DQ<22>")
	)
	(arc
		(start 91.617292 -228.785928)
		(mid 91.431907 -228.833598)
		(end 91.247214 -228.783388)
		(width 0.088646)
		(layer "In4.Cu")
		(net "M_C_CPU1_SB_DQ<22>")
	)
	(arc
		(start 85.983064 -228.783388)
		(mid 85.795866 -228.833531)
		(end 85.608668 -228.783388)
		(width 0.088646)
		(layer "In4.Cu")
		(net "M_C_CPU1_SB_DQ<22>")
	)
	(arc
		(start 87.858346 -228.785928)
		(mid 87.672851 -228.833597)
		(end 87.488014 -228.783388)
		(width 0.088646)
		(layer "In4.Cu")
		(net "M_C_CPU1_SB_DQ<22>")
	)
	(arc
		(start 88.79967 -228.784912)
		(mid 88.613531 -228.83359)
		(end 88.427814 -228.783388)
		(width 0.088646)
		(layer "In4.Cu")
		(net "M_C_CPU1_SB_DQ<22>")
	)
	(arc
		(start 90.307414 -228.783388)
		(mid 90.029091 -228.707629)
		(end 89.74963 -228.77907)
		(width 0.088646)
		(layer "In4.Cu")
		(net "M_C_CPU1_SB_DQ<22>")
	)
	(arc
		(start 85.608668 -228.783388)
		(mid 85.325966 -228.707612)
		(end 85.043264 -228.783388)
		(width 0.088646)
		(layer "In4.Cu")
		(net "M_C_CPU1_SB_DQ<22>")
	)
	(arc
		(start 92.187014 -228.783388)
		(mid 91.908691 -228.707629)
		(end 91.62923 -228.77907)
		(width 0.088646)
		(layer "In4.Cu")
		(net "M_C_CPU1_SB_DQ<22>")
	)
	(arc
		(start 86.548468 -228.783388)
		(mid 86.265766 -228.707612)
		(end 85.983064 -228.783388)
		(width 0.088646)
		(layer "In4.Cu")
		(net "M_C_CPU1_SB_DQ<22>")
	)
	(arc
		(start 84.668868 -228.783388)
		(mid 84.386166 -228.707612)
		(end 84.103464 -228.783388)
		(width 0.088646)
		(layer "In4.Cu")
		(net "M_C_CPU1_SB_DQ<22>")
	)
	(arc
		(start 89.367614 -228.783388)
		(mid 89.089291 -228.707629)
		(end 88.80983 -228.77907)
		(width 0.088646)
		(layer "In4.Cu")
		(net "M_C_CPU1_SB_DQ<22>")
	)
	(arc
		(start 90.677492 -228.785928)
		(mid 90.492107 -228.833598)
		(end 90.307414 -228.783388)
		(width 0.088646)
		(layer "In4.Cu")
		(net "M_C_CPU1_SB_DQ<22>")
	)
	(segment
		(start 24.773636 -206.028036)
		(end 25.27808 -206.028036)
		(width 0.20066)
		(layer "F.Cu")
		(net "M_C_CPU1_SB_DQ<21>")
	)
	(segment
		(start 25.27808 -206.028036)
		(end 25.432512 -205.873604)
		(width 0.20066)
		(layer "F.Cu")
		(net "M_C_CPU1_SB_DQ<21>")
	)
	(segment
		(start 23.228046 -205.816708)
		(end 24.562308 -205.816708)
		(width 0.20066)
		(layer "F.Cu")
		(net "M_C_CPU1_SB_DQ<21>")
	)
	(segment
		(start 24.562308 -205.816708)
		(end 24.773636 -206.028036)
		(width 0.20066)
		(layer "F.Cu")
		(net "M_C_CPU1_SB_DQ<21>")
	)
	(segment
		(start 25.595072 -205.382876)
		(end 26.20391 -205.382876)
		(width 0.20066)
		(layer "F.Cu")
		(net "M_C_CPU1_SB_DQ<21>")
	)
	(segment
		(start 31.876746 -205.816708)
		(end 30.771846 -205.816708)
		(width 0.20066)
		(layer "F.Cu")
		(net "M_C_CPU1_SB_DQ<21>")
	)
	(segment
		(start 25.432512 -205.873604)
		(end 25.432512 -205.545436)
		(width 0.20066)
		(layer "F.Cu")
		(net "M_C_CPU1_SB_DQ<21>")
	)
	(segment
		(start 26.2128 -205.391766)
		(end 28.198318 -205.391766)
		(width 0.1016)
		(layer "F.Cu")
		(net "M_C_CPU1_SB_DQ<21>")
	)
	(segment
		(start 25.432512 -205.545436)
		(end 25.595072 -205.382876)
		(width 0.20066)
		(layer "F.Cu")
		(net "M_C_CPU1_SB_DQ<21>")
	)
	(segment
		(start 92.374466 -228.99497)
		(end 92.374212 -228.994716)
		(width 0.20066)
		(layer "F.Cu")
		(net "M_C_CPU1_SB_DQ<21>")
	)
	(segment
		(start 92.374212 -228.994716)
		(end 92.374212 -228.45903)
		(width 0.20066)
		(layer "F.Cu")
		(net "M_C_CPU1_SB_DQ<21>")
	)
	(segment
		(start 28.529026 -205.391766)
		(end 28.707588 -205.391766)
		(width 0.20066)
		(layer "F.Cu")
		(net "M_C_CPU1_SB_DQ<21>")
	)
	(segment
		(start 28.707588 -205.391766)
		(end 29.13253 -205.816708)
		(width 0.20066)
		(layer "F.Cu")
		(net "M_C_CPU1_SB_DQ<21>")
	)
	(segment
		(start 28.198318 -205.391766)
		(end 28.529026 -205.391766)
		(width 0.101854)
		(layer "F.Cu")
		(net "M_C_CPU1_SB_DQ<21>")
	)
	(segment
		(start 26.20391 -205.382876)
		(end 26.2128 -205.391766)
		(width 0.1016)
		(layer "F.Cu")
		(net "M_C_CPU1_SB_DQ<21>")
	)
	(segment
		(start 29.13253 -205.816708)
		(end 30.771846 -205.816708)
		(width 0.20066)
		(layer "F.Cu")
		(net "M_C_CPU1_SB_DQ<21>")
	)
	(segment
		(start 84.118196 -228.143308)
		(end 84.108544 -228.143308)
		(width 0.088646)
		(layer "In4.Cu")
		(net "M_C_CPU1_SB_DQ<21>")
	)
	(segment
		(start 82.708496 -226.859592)
		(end 78.74 -226.859592)
		(width 0.18288)
		(layer "In4.Cu")
		(net "M_C_CPU1_SB_DQ<21>")
	)
	(segment
		(start 91.247468 -228.134672)
		(end 91.237054 -228.140768)
		(width 0.088646)
		(layer "In4.Cu")
		(net "M_C_CPU1_SB_DQ<21>")
	)
	(segment
		(start 86.937596 -228.143308)
		(end 86.922864 -228.134672)
		(width 0.088646)
		(layer "In4.Cu")
		(net "M_C_CPU1_SB_DQ<21>")
	)
	(segment
		(start 83.499706 -227.53447)
		(end 83.499706 -227.390452)
		(width 0.088646)
		(layer "In4.Cu")
		(net "M_C_CPU1_SB_DQ<21>")
	)
	(segment
		(start 36.97605 -206.112872)
		(end 36.255198 -205.39202)
		(width 0.18288)
		(layer "In4.Cu")
		(net "M_C_CPU1_SB_DQ<21>")
	)
	(segment
		(start 32.301434 -205.39202)
		(end 31.876746 -205.816708)
		(width 0.18288)
		(layer "In4.Cu")
		(net "M_C_CPU1_SB_DQ<21>")
	)
	(segment
		(start 50.541682 -206.241904)
		(end 49.691544 -207.092042)
		(width 0.18288)
		(layer "In4.Cu")
		(net "M_C_CPU1_SB_DQ<21>")
	)
	(segment
		(start 59.251342 -207.320388)
		(end 58.85688 -206.925926)
		(width 0.18288)
		(layer "In4.Cu")
		(net "M_C_CPU1_SB_DQ<21>")
	)
	(segment
		(start 68.243196 -209.686144)
		(end 66.877692 -208.32064)
		(width 0.18288)
		(layer "In4.Cu")
		(net "M_C_CPU1_SB_DQ<21>")
	)
	(segment
		(start 92.68714 -228.45903)
		(end 92.74429 -228.40188)
		(width 0.088646)
		(layer "In4.Cu")
		(net "M_C_CPU1_SB_DQ<21>")
	)
	(segment
		(start 90.307414 -228.134672)
		(end 90.292682 -228.143308)
		(width 0.088646)
		(layer "In4.Cu")
		(net "M_C_CPU1_SB_DQ<21>")
	)
	(segment
		(start 88.427814 -228.134672)
		(end 88.4174 -228.140768)
		(width 0.088646)
		(layer "In4.Cu")
		(net "M_C_CPU1_SB_DQ<21>")
	)
	(segment
		(start 84.108544 -228.143308)
		(end 83.499706 -227.53447)
		(width 0.088646)
		(layer "In4.Cu")
		(net "M_C_CPU1_SB_DQ<21>")
	)
	(segment
		(start 49.691544 -207.092042)
		(end 43.972734 -207.092042)
		(width 0.18288)
		(layer "In4.Cu")
		(net "M_C_CPU1_SB_DQ<21>")
	)
	(segment
		(start 92.5703 -228.139752)
		(end 92.56141 -228.134672)
		(width 0.088646)
		(layer "In4.Cu")
		(net "M_C_CPU1_SB_DQ<21>")
	)
	(segment
		(start 36.255198 -205.39202)
		(end 32.301434 -205.39202)
		(width 0.18288)
		(layer "In4.Cu")
		(net "M_C_CPU1_SB_DQ<21>")
	)
	(segment
		(start 91.632278 -228.140768)
		(end 91.621864 -228.134672)
		(width 0.088646)
		(layer "In4.Cu")
		(net "M_C_CPU1_SB_DQ<21>")
	)
	(segment
		(start 62.860682 -207.320388)
		(end 59.251342 -207.320388)
		(width 0.18288)
		(layer "In4.Cu")
		(net "M_C_CPU1_SB_DQ<21>")
	)
	(segment
		(start 92.374212 -228.45903)
		(end 92.68714 -228.45903)
		(width 0.088646)
		(layer "In4.Cu")
		(net "M_C_CPU1_SB_DQ<21>")
	)
	(segment
		(start 54.819804 -206.241904)
		(end 50.541682 -206.241904)
		(width 0.18288)
		(layer "In4.Cu")
		(net "M_C_CPU1_SB_DQ<21>")
	)
	(segment
		(start 43.972734 -207.092042)
		(end 43.20921 -206.328518)
		(width 0.18288)
		(layer "In4.Cu")
		(net "M_C_CPU1_SB_DQ<21>")
	)
	(segment
		(start 63.860934 -208.32064)
		(end 62.860682 -207.320388)
		(width 0.18288)
		(layer "In4.Cu")
		(net "M_C_CPU1_SB_DQ<21>")
	)
	(segment
		(start 40.86098 -206.328518)
		(end 40.645334 -206.112872)
		(width 0.18288)
		(layer "In4.Cu")
		(net "M_C_CPU1_SB_DQ<21>")
	)
	(segment
		(start 66.877692 -208.32064)
		(end 63.860934 -208.32064)
		(width 0.18288)
		(layer "In4.Cu")
		(net "M_C_CPU1_SB_DQ<21>")
	)
	(segment
		(start 83.499706 -227.390452)
		(end 82.968846 -226.859592)
		(width 0.088646)
		(layer "In4.Cu")
		(net "M_C_CPU1_SB_DQ<21>")
	)
	(segment
		(start 40.645334 -206.112872)
		(end 36.97605 -206.112872)
		(width 0.18288)
		(layer "In4.Cu")
		(net "M_C_CPU1_SB_DQ<21>")
	)
	(segment
		(start 43.20921 -206.328518)
		(end 40.86098 -206.328518)
		(width 0.18288)
		(layer "In4.Cu")
		(net "M_C_CPU1_SB_DQ<21>")
	)
	(segment
		(start 58.85688 -206.925926)
		(end 55.503826 -206.925926)
		(width 0.18288)
		(layer "In4.Cu")
		(net "M_C_CPU1_SB_DQ<21>")
	)
	(segment
		(start 78.74 -226.859592)
		(end 72.964294 -221.083886)
		(width 0.18288)
		(layer "In4.Cu")
		(net "M_C_CPU1_SB_DQ<21>")
	)
	(segment
		(start 72.964294 -221.083886)
		(end 68.243196 -209.686144)
		(width 0.18288)
		(layer "In4.Cu")
		(net "M_C_CPU1_SB_DQ<21>")
	)
	(segment
		(start 82.968846 -226.859592)
		(end 82.708496 -226.859592)
		(width 0.088646)
		(layer "In4.Cu")
		(net "M_C_CPU1_SB_DQ<21>")
	)
	(segment
		(start 55.503826 -206.925926)
		(end 54.819804 -206.241904)
		(width 0.18288)
		(layer "In4.Cu")
		(net "M_C_CPU1_SB_DQ<21>")
	)
	(segment
		(start 89.367614 -228.134672)
		(end 89.352882 -228.143308)
		(width 0.088646)
		(layer "In4.Cu")
		(net "M_C_CPU1_SB_DQ<21>")
	)
	(arc
		(start 92.56141 -228.134672)
		(mid 92.374212 -228.084529)
		(end 92.187014 -228.134672)
		(width 0.088646)
		(layer "In4.Cu")
		(net "M_C_CPU1_SB_DQ<21>")
	)
	(arc
		(start 89.352882 -228.143308)
		(mid 89.076441 -228.210474)
		(end 88.80221 -228.134672)
		(width 0.088646)
		(layer "In4.Cu")
		(net "M_C_CPU1_SB_DQ<21>")
	)
	(arc
		(start 90.292682 -228.143308)
		(mid 90.016241 -228.210474)
		(end 89.74201 -228.134672)
		(width 0.088646)
		(layer "In4.Cu")
		(net "M_C_CPU1_SB_DQ<21>")
	)
	(arc
		(start 84.6836 -228.143308)
		(mid 84.400898 -228.210859)
		(end 84.118196 -228.143308)
		(width 0.088646)
		(layer "In4.Cu")
		(net "M_C_CPU1_SB_DQ<21>")
	)
	(arc
		(start 87.862664 -228.134672)
		(mid 87.675466 -228.084529)
		(end 87.488268 -228.134672)
		(width 0.088646)
		(layer "In4.Cu")
		(net "M_C_CPU1_SB_DQ<21>")
	)
	(arc
		(start 91.237054 -228.140768)
		(mid 90.958622 -228.210582)
		(end 90.68181 -228.134672)
		(width 0.088646)
		(layer "In4.Cu")
		(net "M_C_CPU1_SB_DQ<21>")
	)
	(arc
		(start 87.488268 -228.134672)
		(mid 87.214039 -228.210597)
		(end 86.937596 -228.143308)
		(width 0.088646)
		(layer "In4.Cu")
		(net "M_C_CPU1_SB_DQ<21>")
	)
	(arc
		(start 86.922864 -228.134672)
		(mid 86.735666 -228.084529)
		(end 86.548468 -228.134672)
		(width 0.088646)
		(layer "In4.Cu")
		(net "M_C_CPU1_SB_DQ<21>")
	)
	(arc
		(start 92.74429 -228.40188)
		(mid 92.686171 -228.251639)
		(end 92.5703 -228.139752)
		(width 0.088646)
		(layer "In4.Cu")
		(net "M_C_CPU1_SB_DQ<21>")
	)
	(arc
		(start 85.608668 -228.134672)
		(mid 85.334439 -228.210597)
		(end 85.057996 -228.143308)
		(width 0.088646)
		(layer "In4.Cu")
		(net "M_C_CPU1_SB_DQ<21>")
	)
	(arc
		(start 92.187014 -228.134672)
		(mid 91.910455 -228.210381)
		(end 91.632278 -228.140768)
		(width 0.088646)
		(layer "In4.Cu")
		(net "M_C_CPU1_SB_DQ<21>")
	)
	(arc
		(start 85.983064 -228.134672)
		(mid 85.795866 -228.084529)
		(end 85.608668 -228.134672)
		(width 0.088646)
		(layer "In4.Cu")
		(net "M_C_CPU1_SB_DQ<21>")
	)
	(arc
		(start 88.80221 -228.134672)
		(mid 88.615012 -228.084529)
		(end 88.427814 -228.134672)
		(width 0.088646)
		(layer "In4.Cu")
		(net "M_C_CPU1_SB_DQ<21>")
	)
	(arc
		(start 85.057996 -228.143308)
		(mid 84.870798 -228.093165)
		(end 84.6836 -228.143308)
		(width 0.088646)
		(layer "In4.Cu")
		(net "M_C_CPU1_SB_DQ<21>")
	)
	(arc
		(start 90.68181 -228.134672)
		(mid 90.494612 -228.084529)
		(end 90.307414 -228.134672)
		(width 0.088646)
		(layer "In4.Cu")
		(net "M_C_CPU1_SB_DQ<21>")
	)
	(arc
		(start 91.621864 -228.134672)
		(mid 91.434666 -228.084529)
		(end 91.247468 -228.134672)
		(width 0.088646)
		(layer "In4.Cu")
		(net "M_C_CPU1_SB_DQ<21>")
	)
	(arc
		(start 86.548468 -228.134672)
		(mid 86.265766 -228.210414)
		(end 85.983064 -228.134672)
		(width 0.088646)
		(layer "In4.Cu")
		(net "M_C_CPU1_SB_DQ<21>")
	)
	(arc
		(start 88.4174 -228.140768)
		(mid 88.139222 -228.21046)
		(end 87.862664 -228.134672)
		(width 0.088646)
		(layer "In4.Cu")
		(net "M_C_CPU1_SB_DQ<21>")
	)
	(arc
		(start 89.74201 -228.134672)
		(mid 89.554812 -228.084529)
		(end 89.367614 -228.134672)
		(width 0.088646)
		(layer "In4.Cu")
		(net "M_C_CPU1_SB_DQ<21>")
	)
	(segment
		(start 25.432512 -207.58277)
		(end 25.432512 -207.29321)
		(width 0.20066)
		(layer "F.Cu")
		(net "M_C_CPU1_SB_DQ<20>")
	)
	(segment
		(start 25.642062 -207.08366)
		(end 26.20391 -207.08366)
		(width 0.20066)
		(layer "F.Cu")
		(net "M_C_CPU1_SB_DQ<20>")
	)
	(segment
		(start 24.801068 -207.75549)
		(end 25.259792 -207.75549)
		(width 0.20066)
		(layer "F.Cu")
		(net "M_C_CPU1_SB_DQ<20>")
	)
	(segment
		(start 24.562308 -207.51673)
		(end 24.801068 -207.75549)
		(width 0.20066)
		(layer "F.Cu")
		(net "M_C_CPU1_SB_DQ<20>")
	)
	(segment
		(start 26.459942 -207.091788)
		(end 28.529026 -207.091788)
		(width 0.1016)
		(layer "F.Cu")
		(net "M_C_CPU1_SB_DQ<20>")
	)
	(segment
		(start 26.212038 -207.091788)
		(end 26.459942 -207.091788)
		(width 0.101854)
		(layer "F.Cu")
		(net "M_C_CPU1_SB_DQ<20>")
	)
	(segment
		(start 28.977844 -207.091788)
		(end 29.402786 -207.51673)
		(width 0.20066)
		(layer "F.Cu")
		(net "M_C_CPU1_SB_DQ<20>")
	)
	(segment
		(start 28.529026 -207.091788)
		(end 28.977844 -207.091788)
		(width 0.20066)
		(layer "F.Cu")
		(net "M_C_CPU1_SB_DQ<20>")
	)
	(segment
		(start 25.432512 -207.29321)
		(end 25.642062 -207.08366)
		(width 0.20066)
		(layer "F.Cu")
		(net "M_C_CPU1_SB_DQ<20>")
	)
	(segment
		(start 31.876746 -207.51673)
		(end 30.771846 -207.51673)
		(width 0.20066)
		(layer "F.Cu")
		(net "M_C_CPU1_SB_DQ<20>")
	)
	(segment
		(start 23.228046 -207.51673)
		(end 24.562308 -207.51673)
		(width 0.20066)
		(layer "F.Cu")
		(net "M_C_CPU1_SB_DQ<20>")
	)
	(segment
		(start 26.20391 -207.08366)
		(end 26.212038 -207.091788)
		(width 0.101854)
		(layer "F.Cu")
		(net "M_C_CPU1_SB_DQ<20>")
	)
	(segment
		(start 25.259792 -207.75549)
		(end 25.432512 -207.58277)
		(width 0.20066)
		(layer "F.Cu")
		(net "M_C_CPU1_SB_DQ<20>")
	)
	(segment
		(start 91.904566 -229.808532)
		(end 91.904566 -229.272846)
		(width 0.20066)
		(layer "F.Cu")
		(net "M_C_CPU1_SB_DQ<20>")
	)
	(segment
		(start 91.904312 -229.808786)
		(end 91.904566 -229.808532)
		(width 0.20066)
		(layer "F.Cu")
		(net "M_C_CPU1_SB_DQ<20>")
	)
	(segment
		(start 29.402786 -207.51673)
		(end 30.771846 -207.51673)
		(width 0.20066)
		(layer "F.Cu")
		(net "M_C_CPU1_SB_DQ<20>")
	)
	(segment
		(start 66.461386 -209.521044)
		(end 63.501016 -209.521044)
		(width 0.18288)
		(layer "In4.Cu")
		(net "M_C_CPU1_SB_DQ<20>")
	)
	(segment
		(start 72.171052 -221.77121)
		(end 67.545712 -210.60537)
		(width 0.18288)
		(layer "In4.Cu")
		(net "M_C_CPU1_SB_DQ<20>")
	)
	(segment
		(start 35.245294 -208.12252)
		(end 35.062414 -207.93964)
		(width 0.18288)
		(layer "In4.Cu")
		(net "M_C_CPU1_SB_DQ<20>")
	)
	(segment
		(start 84.198968 -228.948488)
		(end 84.077556 -229.018592)
		(width 0.088646)
		(layer "In4.Cu")
		(net "M_C_CPU1_SB_DQ<20>")
	)
	(segment
		(start 34.879534 -206.11846)
		(end 34.554414 -206.11846)
		(width 0.18288)
		(layer "In4.Cu")
		(net "M_C_CPU1_SB_DQ<20>")
	)
	(segment
		(start 35.733228 -207.941672)
		(end 35.55238 -208.12252)
		(width 0.18288)
		(layer "In4.Cu")
		(net "M_C_CPU1_SB_DQ<20>")
	)
	(segment
		(start 88.897714 -228.948234)
		(end 88.892126 -228.951536)
		(width 0.088646)
		(layer "In4.Cu")
		(net "M_C_CPU1_SB_DQ<20>")
	)
	(segment
		(start 35.062414 -207.93964)
		(end 35.062414 -206.30134)
		(width 0.18288)
		(layer "In4.Cu")
		(net "M_C_CPU1_SB_DQ<20>")
	)
	(segment
		(start 63.501016 -209.521044)
		(end 62.79642 -208.816448)
		(width 0.18288)
		(layer "In4.Cu")
		(net "M_C_CPU1_SB_DQ<20>")
	)
	(segment
		(start 90.777314 -228.948234)
		(end 90.769948 -228.952552)
		(width 0.088646)
		(layer "In4.Cu")
		(net "M_C_CPU1_SB_DQ<20>")
	)
	(segment
		(start 83.003644 -227.855272)
		(end 82.708496 -227.855272)
		(width 0.088646)
		(layer "In4.Cu")
		(net "M_C_CPU1_SB_DQ<20>")
	)
	(segment
		(start 83.643978 -228.799898)
		(end 83.643978 -228.495606)
		(width 0.088646)
		(layer "In4.Cu")
		(net "M_C_CPU1_SB_DQ<20>")
	)
	(segment
		(start 83.643978 -228.495606)
		(end 83.003644 -227.855272)
		(width 0.088646)
		(layer "In4.Cu")
		(net "M_C_CPU1_SB_DQ<20>")
	)
	(segment
		(start 43.092624 -208.79181)
		(end 42.242486 -207.941672)
		(width 0.18288)
		(layer "In4.Cu")
		(net "M_C_CPU1_SB_DQ<20>")
	)
	(segment
		(start 34.371534 -206.30134)
		(end 34.371534 -207.93964)
		(width 0.18288)
		(layer "In4.Cu")
		(net "M_C_CPU1_SB_DQ<20>")
	)
	(segment
		(start 82.708496 -227.855272)
		(end 78.255114 -227.855272)
		(width 0.18288)
		(layer "In4.Cu")
		(net "M_C_CPU1_SB_DQ<20>")
	)
	(segment
		(start 87.957914 -228.948234)
		(end 87.952834 -228.951282)
		(width 0.088646)
		(layer "In4.Cu")
		(net "M_C_CPU1_SB_DQ<20>")
	)
	(segment
		(start 83.862672 -229.018592)
		(end 83.643978 -228.799898)
		(width 0.088646)
		(layer "In4.Cu")
		(net "M_C_CPU1_SB_DQ<20>")
	)
	(segment
		(start 89.837514 -228.948234)
		(end 89.830148 -228.952552)
		(width 0.088646)
		(layer "In4.Cu")
		(net "M_C_CPU1_SB_DQ<20>")
	)
	(segment
		(start 34.188654 -208.12252)
		(end 32.482536 -208.12252)
		(width 0.18288)
		(layer "In4.Cu")
		(net "M_C_CPU1_SB_DQ<20>")
	)
	(segment
		(start 78.255114 -227.855272)
		(end 72.171052 -221.77121)
		(width 0.18288)
		(layer "In4.Cu")
		(net "M_C_CPU1_SB_DQ<20>")
	)
	(segment
		(start 35.55238 -208.12252)
		(end 35.245294 -208.12252)
		(width 0.18288)
		(layer "In4.Cu")
		(net "M_C_CPU1_SB_DQ<20>")
	)
	(segment
		(start 42.242486 -207.941672)
		(end 35.733228 -207.941672)
		(width 0.18288)
		(layer "In4.Cu")
		(net "M_C_CPU1_SB_DQ<20>")
	)
	(segment
		(start 49.66335 -208.79181)
		(end 43.092624 -208.79181)
		(width 0.18288)
		(layer "In4.Cu")
		(net "M_C_CPU1_SB_DQ<20>")
	)
	(segment
		(start 52.341526 -207.941672)
		(end 50.513488 -207.941672)
		(width 0.18288)
		(layer "In4.Cu")
		(net "M_C_CPU1_SB_DQ<20>")
	)
	(segment
		(start 91.548458 -229.177342)
		(end 91.151964 -228.948234)
		(width 0.088646)
		(layer "In4.Cu")
		(net "M_C_CPU1_SB_DQ<20>")
	)
	(segment
		(start 88.902286 -228.945694)
		(end 88.897714 -228.948234)
		(width 0.088646)
		(layer "In4.Cu")
		(net "M_C_CPU1_SB_DQ<20>")
	)
	(segment
		(start 62.79642 -208.816448)
		(end 53.216302 -208.816448)
		(width 0.18288)
		(layer "In4.Cu")
		(net "M_C_CPU1_SB_DQ<20>")
	)
	(segment
		(start 89.842086 -228.945694)
		(end 89.837514 -228.948234)
		(width 0.088646)
		(layer "In4.Cu")
		(net "M_C_CPU1_SB_DQ<20>")
	)
	(segment
		(start 84.077556 -229.018592)
		(end 83.862672 -229.018592)
		(width 0.088646)
		(layer "In4.Cu")
		(net "M_C_CPU1_SB_DQ<20>")
	)
	(segment
		(start 32.482536 -208.12252)
		(end 31.876746 -207.51673)
		(width 0.18288)
		(layer "In4.Cu")
		(net "M_C_CPU1_SB_DQ<20>")
	)
	(segment
		(start 35.062414 -206.30134)
		(end 34.879534 -206.11846)
		(width 0.18288)
		(layer "In4.Cu")
		(net "M_C_CPU1_SB_DQ<20>")
	)
	(segment
		(start 34.554414 -206.11846)
		(end 34.371534 -206.30134)
		(width 0.18288)
		(layer "In4.Cu")
		(net "M_C_CPU1_SB_DQ<20>")
	)
	(segment
		(start 53.216302 -208.816448)
		(end 52.341526 -207.941672)
		(width 0.18288)
		(layer "In4.Cu")
		(net "M_C_CPU1_SB_DQ<20>")
	)
	(segment
		(start 67.545712 -210.60537)
		(end 66.461386 -209.521044)
		(width 0.18288)
		(layer "In4.Cu")
		(net "M_C_CPU1_SB_DQ<20>")
	)
	(segment
		(start 91.904566 -229.272846)
		(end 91.904312 -229.272592)
		(width 0.088646)
		(layer "In4.Cu")
		(net "M_C_CPU1_SB_DQ<20>")
	)
	(segment
		(start 90.781886 -228.945694)
		(end 90.777314 -228.948234)
		(width 0.088646)
		(layer "In4.Cu")
		(net "M_C_CPU1_SB_DQ<20>")
	)
	(segment
		(start 34.371534 -207.93964)
		(end 34.188654 -208.12252)
		(width 0.18288)
		(layer "In4.Cu")
		(net "M_C_CPU1_SB_DQ<20>")
	)
	(segment
		(start 50.513488 -207.941672)
		(end 49.66335 -208.79181)
		(width 0.18288)
		(layer "In4.Cu")
		(net "M_C_CPU1_SB_DQ<20>")
	)
	(arc
		(start 89.830148 -228.952552)
		(mid 89.550687 -229.024021)
		(end 89.272364 -228.948234)
		(width 0.088646)
		(layer "In4.Cu")
		(net "M_C_CPU1_SB_DQ<20>")
	)
	(arc
		(start 87.952834 -228.951282)
		(mid 87.672424 -229.024166)
		(end 87.392764 -228.948488)
		(width 0.088646)
		(layer "In4.Cu")
		(net "M_C_CPU1_SB_DQ<20>")
	)
	(arc
		(start 88.892126 -228.951536)
		(mid 88.611911 -229.02401)
		(end 88.332564 -228.948234)
		(width 0.088646)
		(layer "In4.Cu")
		(net "M_C_CPU1_SB_DQ<20>")
	)
	(arc
		(start 85.138768 -228.948488)
		(mid 84.856066 -229.024264)
		(end 84.573364 -228.948488)
		(width 0.088646)
		(layer "In4.Cu")
		(net "M_C_CPU1_SB_DQ<20>")
	)
	(arc
		(start 86.452964 -228.948488)
		(mid 86.265766 -228.898345)
		(end 86.078568 -228.948488)
		(width 0.088646)
		(layer "In4.Cu")
		(net "M_C_CPU1_SB_DQ<20>")
	)
	(arc
		(start 84.573364 -228.948488)
		(mid 84.386166 -228.898345)
		(end 84.198968 -228.948488)
		(width 0.088646)
		(layer "In4.Cu")
		(net "M_C_CPU1_SB_DQ<20>")
	)
	(arc
		(start 86.078568 -228.948488)
		(mid 85.795866 -229.024264)
		(end 85.513164 -228.948488)
		(width 0.088646)
		(layer "In4.Cu")
		(net "M_C_CPU1_SB_DQ<20>")
	)
	(arc
		(start 90.212164 -228.948234)
		(mid 90.02747 -228.898133)
		(end 89.842086 -228.945694)
		(width 0.088646)
		(layer "In4.Cu")
		(net "M_C_CPU1_SB_DQ<20>")
	)
	(arc
		(start 89.272364 -228.948234)
		(mid 89.08767 -228.898133)
		(end 88.902286 -228.945694)
		(width 0.088646)
		(layer "In4.Cu")
		(net "M_C_CPU1_SB_DQ<20>")
	)
	(arc
		(start 87.392764 -228.948488)
		(mid 87.205566 -228.898345)
		(end 87.018368 -228.948488)
		(width 0.088646)
		(layer "In4.Cu")
		(net "M_C_CPU1_SB_DQ<20>")
	)
	(arc
		(start 91.151964 -228.948234)
		(mid 90.96727 -228.898133)
		(end 90.781886 -228.945694)
		(width 0.088646)
		(layer "In4.Cu")
		(net "M_C_CPU1_SB_DQ<20>")
	)
	(arc
		(start 88.332564 -228.948234)
		(mid 88.145256 -228.898125)
		(end 87.957914 -228.948234)
		(width 0.088646)
		(layer "In4.Cu")
		(net "M_C_CPU1_SB_DQ<20>")
	)
	(arc
		(start 90.769948 -228.952552)
		(mid 90.490487 -229.024021)
		(end 90.212164 -228.948234)
		(width 0.088646)
		(layer "In4.Cu")
		(net "M_C_CPU1_SB_DQ<20>")
	)
	(arc
		(start 85.513164 -228.948488)
		(mid 85.325966 -228.898345)
		(end 85.138768 -228.948488)
		(width 0.088646)
		(layer "In4.Cu")
		(net "M_C_CPU1_SB_DQ<20>")
	)
	(arc
		(start 87.018368 -228.948488)
		(mid 86.735666 -229.024264)
		(end 86.452964 -228.948488)
		(width 0.088646)
		(layer "In4.Cu")
		(net "M_C_CPU1_SB_DQ<20>")
	)
	(arc
		(start 91.904312 -229.272592)
		(mid 91.720108 -229.248409)
		(end 91.548458 -229.177342)
		(width 0.088646)
		(layer "In4.Cu")
		(net "M_C_CPU1_SB_DQ<20>")
	)
	(segment
		(start 29.13253 -230.466646)
		(end 30.771846 -230.466646)
		(width 0.20066)
		(layer "F.Cu")
		(net "M_C_CPU1_SB_DQ<1>")
	)
	(segment
		(start 26.20391 -230.032814)
		(end 26.2128 -230.041704)
		(width 0.1016)
		(layer "F.Cu")
		(net "M_C_CPU1_SB_DQ<1>")
	)
	(segment
		(start 26.2128 -230.041704)
		(end 28.198318 -230.041704)
		(width 0.1016)
		(layer "F.Cu")
		(net "M_C_CPU1_SB_DQ<1>")
	)
	(segment
		(start 25.27808 -230.677974)
		(end 25.432512 -230.523542)
		(width 0.20066)
		(layer "F.Cu")
		(net "M_C_CPU1_SB_DQ<1>")
	)
	(segment
		(start 25.595072 -230.032814)
		(end 26.20391 -230.032814)
		(width 0.20066)
		(layer "F.Cu")
		(net "M_C_CPU1_SB_DQ<1>")
	)
	(segment
		(start 31.876746 -230.466646)
		(end 30.771846 -230.466646)
		(width 0.20066)
		(layer "F.Cu")
		(net "M_C_CPU1_SB_DQ<1>")
	)
	(segment
		(start 28.707588 -230.041704)
		(end 29.13253 -230.466646)
		(width 0.20066)
		(layer "F.Cu")
		(net "M_C_CPU1_SB_DQ<1>")
	)
	(segment
		(start 24.562308 -230.466646)
		(end 24.773636 -230.677974)
		(width 0.20066)
		(layer "F.Cu")
		(net "M_C_CPU1_SB_DQ<1>")
	)
	(segment
		(start 25.432512 -230.523542)
		(end 25.432512 -230.195374)
		(width 0.20066)
		(layer "F.Cu")
		(net "M_C_CPU1_SB_DQ<1>")
	)
	(segment
		(start 95.193866 -243.644928)
		(end 95.193612 -243.644674)
		(width 0.20066)
		(layer "F.Cu")
		(net "M_C_CPU1_SB_DQ<1>")
	)
	(segment
		(start 28.198318 -230.041704)
		(end 28.529026 -230.041704)
		(width 0.101854)
		(layer "F.Cu")
		(net "M_C_CPU1_SB_DQ<1>")
	)
	(segment
		(start 95.193612 -243.644674)
		(end 95.193612 -243.108988)
		(width 0.20066)
		(layer "F.Cu")
		(net "M_C_CPU1_SB_DQ<1>")
	)
	(segment
		(start 28.529026 -230.041704)
		(end 28.707588 -230.041704)
		(width 0.20066)
		(layer "F.Cu")
		(net "M_C_CPU1_SB_DQ<1>")
	)
	(segment
		(start 23.228046 -230.466646)
		(end 24.562308 -230.466646)
		(width 0.20066)
		(layer "F.Cu")
		(net "M_C_CPU1_SB_DQ<1>")
	)
	(segment
		(start 24.773636 -230.677974)
		(end 25.27808 -230.677974)
		(width 0.20066)
		(layer "F.Cu")
		(net "M_C_CPU1_SB_DQ<1>")
	)
	(segment
		(start 25.432512 -230.195374)
		(end 25.595072 -230.032814)
		(width 0.20066)
		(layer "F.Cu")
		(net "M_C_CPU1_SB_DQ<1>")
	)
	(segment
		(start 49.847754 -235.991654)
		(end 48.99787 -235.14177)
		(width 0.18288)
		(layer "In6.Cu")
		(net "M_C_CPU1_SB_DQ<1>")
	)
	(segment
		(start 89.843356 -243.595144)
		(end 89.831672 -243.601748)
		(width 0.088646)
		(layer "In6.Cu")
		(net "M_C_CPU1_SB_DQ<1>")
	)
	(segment
		(start 34.374582 -230.891842)
		(end 34.049462 -230.891842)
		(width 0.18288)
		(layer "In6.Cu")
		(net "M_C_CPU1_SB_DQ<1>")
	)
	(segment
		(start 35.065462 -231.66832)
		(end 34.740342 -231.66832)
		(width 0.18288)
		(layer "In6.Cu")
		(net "M_C_CPU1_SB_DQ<1>")
	)
	(segment
		(start 34.557462 -231.48544)
		(end 34.557462 -231.074722)
		(width 0.18288)
		(layer "In6.Cu")
		(net "M_C_CPU1_SB_DQ<1>")
	)
	(segment
		(start 34.740342 -231.66832)
		(end 34.557462 -231.48544)
		(width 0.18288)
		(layer "In6.Cu")
		(net "M_C_CPU1_SB_DQ<1>")
	)
	(segment
		(start 35.431222 -230.891842)
		(end 35.248342 -231.074722)
		(width 0.18288)
		(layer "In6.Cu")
		(net "M_C_CPU1_SB_DQ<1>")
	)
	(segment
		(start 37.581586 -230.891842)
		(end 35.431222 -230.891842)
		(width 0.18288)
		(layer "In6.Cu")
		(net "M_C_CPU1_SB_DQ<1>")
	)
	(segment
		(start 32.992822 -230.891842)
		(end 32.301942 -230.891842)
		(width 0.18288)
		(layer "In6.Cu")
		(net "M_C_CPU1_SB_DQ<1>")
	)
	(segment
		(start 33.866582 -231.48544)
		(end 33.683702 -231.66832)
		(width 0.18288)
		(layer "In6.Cu")
		(net "M_C_CPU1_SB_DQ<1>")
	)
	(segment
		(start 87.958168 -243.598446)
		(end 87.947754 -243.604542)
		(width 0.088646)
		(layer "In6.Cu")
		(net "M_C_CPU1_SB_DQ<1>")
	)
	(segment
		(start 87.018114 -243.598446)
		(end 87.003382 -243.607082)
		(width 0.088646)
		(layer "In6.Cu")
		(net "M_C_CPU1_SB_DQ<1>")
	)
	(segment
		(start 35.248342 -231.48544)
		(end 35.065462 -231.66832)
		(width 0.18288)
		(layer "In6.Cu")
		(net "M_C_CPU1_SB_DQ<1>")
	)
	(segment
		(start 32.301942 -230.891842)
		(end 31.876746 -230.466646)
		(width 0.18288)
		(layer "In6.Cu")
		(net "M_C_CPU1_SB_DQ<1>")
	)
	(segment
		(start 84.109052 -243.650262)
		(end 83.971384 -243.650262)
		(width 0.088646)
		(layer "In6.Cu")
		(net "M_C_CPU1_SB_DQ<1>")
	)
	(segment
		(start 83.089496 -243.437918)
		(end 82.839052 -243.437918)
		(width 0.18288)
		(layer "In6.Cu")
		(net "M_C_CPU1_SB_DQ<1>")
	)
	(segment
		(start 33.175702 -231.074722)
		(end 32.992822 -230.891842)
		(width 0.18288)
		(layer "In6.Cu")
		(net "M_C_CPU1_SB_DQ<1>")
	)
	(segment
		(start 35.248342 -231.074722)
		(end 35.248342 -231.48544)
		(width 0.18288)
		(layer "In6.Cu")
		(net "M_C_CPU1_SB_DQ<1>")
	)
	(segment
		(start 85.138514 -243.598446)
		(end 85.123782 -243.607082)
		(width 0.088646)
		(layer "In6.Cu")
		(net "M_C_CPU1_SB_DQ<1>")
	)
	(segment
		(start 86.078314 -243.598446)
		(end 86.063582 -243.607082)
		(width 0.088646)
		(layer "In6.Cu")
		(net "M_C_CPU1_SB_DQ<1>")
	)
	(segment
		(start 94.536514 -243.598446)
		(end 94.530672 -243.601748)
		(width 0.088646)
		(layer "In6.Cu")
		(net "M_C_CPU1_SB_DQ<1>")
	)
	(segment
		(start 64.136016 -237.367826)
		(end 59.39663 -237.367826)
		(width 0.18288)
		(layer "In6.Cu")
		(net "M_C_CPU1_SB_DQ<1>")
	)
	(segment
		(start 59.39663 -237.367826)
		(end 58.583322 -236.554518)
		(width 0.18288)
		(layer "In6.Cu")
		(net "M_C_CPU1_SB_DQ<1>")
	)
	(segment
		(start 90.783156 -243.595144)
		(end 90.771472 -243.601748)
		(width 0.088646)
		(layer "In6.Cu")
		(net "M_C_CPU1_SB_DQ<1>")
	)
	(segment
		(start 70.820026 -242.432332)
		(end 66.988436 -238.600742)
		(width 0.18288)
		(layer "In6.Cu")
		(net "M_C_CPU1_SB_DQ<1>")
	)
	(segment
		(start 38.054026 -231.364282)
		(end 37.581586 -230.891842)
		(width 0.18288)
		(layer "In6.Cu")
		(net "M_C_CPU1_SB_DQ<1>")
	)
	(segment
		(start 94.640908 -243.536978)
		(end 94.536514 -243.598446)
		(width 0.088646)
		(layer "In6.Cu")
		(net "M_C_CPU1_SB_DQ<1>")
	)
	(segment
		(start 92.662756 -243.595144)
		(end 92.651072 -243.601748)
		(width 0.088646)
		(layer "In6.Cu")
		(net "M_C_CPU1_SB_DQ<1>")
	)
	(segment
		(start 81.833466 -242.432332)
		(end 70.820026 -242.432332)
		(width 0.18288)
		(layer "In6.Cu")
		(net "M_C_CPU1_SB_DQ<1>")
	)
	(segment
		(start 83.75904 -243.437918)
		(end 83.089496 -243.437918)
		(width 0.088646)
		(layer "In6.Cu")
		(net "M_C_CPU1_SB_DQ<1>")
	)
	(segment
		(start 48.99787 -235.14177)
		(end 44.013628 -235.14177)
		(width 0.18288)
		(layer "In6.Cu")
		(net "M_C_CPU1_SB_DQ<1>")
	)
	(segment
		(start 66.988436 -238.600742)
		(end 65.368932 -238.600742)
		(width 0.18288)
		(layer "In6.Cu")
		(net "M_C_CPU1_SB_DQ<1>")
	)
	(segment
		(start 65.368932 -238.600742)
		(end 64.136016 -237.367826)
		(width 0.18288)
		(layer "In6.Cu")
		(net "M_C_CPU1_SB_DQ<1>")
	)
	(segment
		(start 39.908226 -231.878886)
		(end 39.138606 -231.878886)
		(width 0.18288)
		(layer "In6.Cu")
		(net "M_C_CPU1_SB_DQ<1>")
	)
	(segment
		(start 33.175702 -231.48544)
		(end 33.175702 -231.074722)
		(width 0.18288)
		(layer "In6.Cu")
		(net "M_C_CPU1_SB_DQ<1>")
	)
	(segment
		(start 93.602556 -243.595144)
		(end 93.590872 -243.601748)
		(width 0.088646)
		(layer "In6.Cu")
		(net "M_C_CPU1_SB_DQ<1>")
	)
	(segment
		(start 84.198714 -243.598446)
		(end 84.109052 -243.650262)
		(width 0.088646)
		(layer "In6.Cu")
		(net "M_C_CPU1_SB_DQ<1>")
	)
	(segment
		(start 33.866582 -231.074722)
		(end 33.866582 -231.48544)
		(width 0.18288)
		(layer "In6.Cu")
		(net "M_C_CPU1_SB_DQ<1>")
	)
	(segment
		(start 55.658512 -236.554518)
		(end 54.809136 -235.705142)
		(width 0.18288)
		(layer "In6.Cu")
		(net "M_C_CPU1_SB_DQ<1>")
	)
	(segment
		(start 38.624002 -231.364282)
		(end 38.054026 -231.364282)
		(width 0.18288)
		(layer "In6.Cu")
		(net "M_C_CPU1_SB_DQ<1>")
	)
	(segment
		(start 82.839052 -243.437918)
		(end 81.833466 -242.432332)
		(width 0.18288)
		(layer "In6.Cu")
		(net "M_C_CPU1_SB_DQ<1>")
	)
	(segment
		(start 58.583322 -236.554518)
		(end 55.658512 -236.554518)
		(width 0.18288)
		(layer "In6.Cu")
		(net "M_C_CPU1_SB_DQ<1>")
	)
	(segment
		(start 88.903556 -243.595144)
		(end 88.897714 -243.598446)
		(width 0.088646)
		(layer "In6.Cu")
		(net "M_C_CPU1_SB_DQ<1>")
	)
	(segment
		(start 34.049462 -230.891842)
		(end 33.866582 -231.074722)
		(width 0.18288)
		(layer "In6.Cu")
		(net "M_C_CPU1_SB_DQ<1>")
	)
	(segment
		(start 95.193612 -243.108988)
		(end 95.193358 -243.108988)
		(width 0.088646)
		(layer "In6.Cu")
		(net "M_C_CPU1_SB_DQ<1>")
	)
	(segment
		(start 54.809136 -235.705142)
		(end 52.004468 -235.705142)
		(width 0.18288)
		(layer "In6.Cu")
		(net "M_C_CPU1_SB_DQ<1>")
	)
	(segment
		(start 44.013628 -235.14177)
		(end 42.151808 -233.27995)
		(width 0.18288)
		(layer "In6.Cu")
		(net "M_C_CPU1_SB_DQ<1>")
	)
	(segment
		(start 83.971384 -243.650262)
		(end 83.75904 -243.437918)
		(width 0.088646)
		(layer "In6.Cu")
		(net "M_C_CPU1_SB_DQ<1>")
	)
	(segment
		(start 52.004468 -235.705142)
		(end 51.717956 -235.991654)
		(width 0.18288)
		(layer "In6.Cu")
		(net "M_C_CPU1_SB_DQ<1>")
	)
	(segment
		(start 41.30929 -233.27995)
		(end 39.908226 -231.878886)
		(width 0.18288)
		(layer "In6.Cu")
		(net "M_C_CPU1_SB_DQ<1>")
	)
	(segment
		(start 34.557462 -231.074722)
		(end 34.374582 -230.891842)
		(width 0.18288)
		(layer "In6.Cu")
		(net "M_C_CPU1_SB_DQ<1>")
	)
	(segment
		(start 88.897714 -243.598446)
		(end 88.893142 -243.600986)
		(width 0.088646)
		(layer "In6.Cu")
		(net "M_C_CPU1_SB_DQ<1>")
	)
	(segment
		(start 33.358582 -231.66832)
		(end 33.175702 -231.48544)
		(width 0.18288)
		(layer "In6.Cu")
		(net "M_C_CPU1_SB_DQ<1>")
	)
	(segment
		(start 33.683702 -231.66832)
		(end 33.358582 -231.66832)
		(width 0.18288)
		(layer "In6.Cu")
		(net "M_C_CPU1_SB_DQ<1>")
	)
	(segment
		(start 91.722956 -243.595144)
		(end 91.711272 -243.601748)
		(width 0.088646)
		(layer "In6.Cu")
		(net "M_C_CPU1_SB_DQ<1>")
	)
	(segment
		(start 39.138606 -231.878886)
		(end 38.624002 -231.364282)
		(width 0.18288)
		(layer "In6.Cu")
		(net "M_C_CPU1_SB_DQ<1>")
	)
	(segment
		(start 42.151808 -233.27995)
		(end 41.30929 -233.27995)
		(width 0.18288)
		(layer "In6.Cu")
		(net "M_C_CPU1_SB_DQ<1>")
	)
	(segment
		(start 51.717956 -235.991654)
		(end 49.847754 -235.991654)
		(width 0.18288)
		(layer "In6.Cu")
		(net "M_C_CPU1_SB_DQ<1>")
	)
	(arc
		(start 93.590872 -243.601748)
		(mid 93.310767 -243.67419)
		(end 93.031564 -243.598446)
		(width 0.088646)
		(layer "In6.Cu")
		(net "M_C_CPU1_SB_DQ<1>")
	)
	(arc
		(start 89.272364 -243.598446)
		(mid 89.08841 -243.548317)
		(end 88.903556 -243.595144)
		(width 0.088646)
		(layer "In6.Cu")
		(net "M_C_CPU1_SB_DQ<1>")
	)
	(arc
		(start 91.151964 -243.598446)
		(mid 90.96801 -243.548317)
		(end 90.783156 -243.595144)
		(width 0.088646)
		(layer "In6.Cu")
		(net "M_C_CPU1_SB_DQ<1>")
	)
	(arc
		(start 87.39251 -243.598446)
		(mid 87.205312 -243.548303)
		(end 87.018114 -243.598446)
		(width 0.088646)
		(layer "In6.Cu")
		(net "M_C_CPU1_SB_DQ<1>")
	)
	(arc
		(start 85.123782 -243.607082)
		(mid 84.847307 -243.674402)
		(end 84.57311 -243.598446)
		(width 0.088646)
		(layer "In6.Cu")
		(net "M_C_CPU1_SB_DQ<1>")
	)
	(arc
		(start 85.51291 -243.598446)
		(mid 85.325712 -243.548303)
		(end 85.138514 -243.598446)
		(width 0.088646)
		(layer "In6.Cu")
		(net "M_C_CPU1_SB_DQ<1>")
	)
	(arc
		(start 86.45271 -243.598446)
		(mid 86.265512 -243.548303)
		(end 86.078314 -243.598446)
		(width 0.088646)
		(layer "In6.Cu")
		(net "M_C_CPU1_SB_DQ<1>")
	)
	(arc
		(start 87.003382 -243.607082)
		(mid 86.726907 -243.674402)
		(end 86.45271 -243.598446)
		(width 0.088646)
		(layer "In6.Cu")
		(net "M_C_CPU1_SB_DQ<1>")
	)
	(arc
		(start 87.947754 -243.604542)
		(mid 87.669322 -243.674388)
		(end 87.39251 -243.598446)
		(width 0.088646)
		(layer "In6.Cu")
		(net "M_C_CPU1_SB_DQ<1>")
	)
	(arc
		(start 88.332564 -243.598446)
		(mid 88.145366 -243.548303)
		(end 87.958168 -243.598446)
		(width 0.088646)
		(layer "In6.Cu")
		(net "M_C_CPU1_SB_DQ<1>")
	)
	(arc
		(start 90.771472 -243.601748)
		(mid 90.491367 -243.67419)
		(end 90.212164 -243.598446)
		(width 0.088646)
		(layer "In6.Cu")
		(net "M_C_CPU1_SB_DQ<1>")
	)
	(arc
		(start 89.831672 -243.601748)
		(mid 89.551567 -243.67419)
		(end 89.272364 -243.598446)
		(width 0.088646)
		(layer "In6.Cu")
		(net "M_C_CPU1_SB_DQ<1>")
	)
	(arc
		(start 95.193358 -243.108988)
		(mid 94.930667 -243.340452)
		(end 94.640908 -243.536978)
		(width 0.088646)
		(layer "In6.Cu")
		(net "M_C_CPU1_SB_DQ<1>")
	)
	(arc
		(start 86.063582 -243.607082)
		(mid 85.787107 -243.674402)
		(end 85.51291 -243.598446)
		(width 0.088646)
		(layer "In6.Cu")
		(net "M_C_CPU1_SB_DQ<1>")
	)
	(arc
		(start 93.971364 -243.598446)
		(mid 93.78741 -243.548317)
		(end 93.602556 -243.595144)
		(width 0.088646)
		(layer "In6.Cu")
		(net "M_C_CPU1_SB_DQ<1>")
	)
	(arc
		(start 94.530672 -243.601748)
		(mid 94.250567 -243.67419)
		(end 93.971364 -243.598446)
		(width 0.088646)
		(layer "In6.Cu")
		(net "M_C_CPU1_SB_DQ<1>")
	)
	(arc
		(start 91.711272 -243.601748)
		(mid 91.431167 -243.67419)
		(end 91.151964 -243.598446)
		(width 0.088646)
		(layer "In6.Cu")
		(net "M_C_CPU1_SB_DQ<1>")
	)
	(arc
		(start 92.091764 -243.598446)
		(mid 91.90781 -243.548317)
		(end 91.722956 -243.595144)
		(width 0.088646)
		(layer "In6.Cu")
		(net "M_C_CPU1_SB_DQ<1>")
	)
	(arc
		(start 92.651072 -243.601748)
		(mid 92.370967 -243.67419)
		(end 92.091764 -243.598446)
		(width 0.088646)
		(layer "In6.Cu")
		(net "M_C_CPU1_SB_DQ<1>")
	)
	(arc
		(start 90.212164 -243.598446)
		(mid 90.02821 -243.548317)
		(end 89.843356 -243.595144)
		(width 0.088646)
		(layer "In6.Cu")
		(net "M_C_CPU1_SB_DQ<1>")
	)
	(arc
		(start 84.57311 -243.598446)
		(mid 84.385912 -243.548303)
		(end 84.198714 -243.598446)
		(width 0.088646)
		(layer "In6.Cu")
		(net "M_C_CPU1_SB_DQ<1>")
	)
	(arc
		(start 88.893142 -243.600986)
		(mid 88.612507 -243.674154)
		(end 88.332564 -243.598446)
		(width 0.088646)
		(layer "In6.Cu")
		(net "M_C_CPU1_SB_DQ<1>")
	)
	(arc
		(start 93.031564 -243.598446)
		(mid 92.84761 -243.548317)
		(end 92.662756 -243.595144)
		(width 0.088646)
		(layer "In6.Cu")
		(net "M_C_CPU1_SB_DQ<1>")
	)
	(segment
		(start 29.661866 -211.341716)
		(end 29.899864 -211.341716)
		(width 0.101854)
		(layer "F.Cu")
		(net "M_C_CPU1_SB_DQ<19>")
	)
	(segment
		(start 29.647642 -211.35594)
		(end 29.661866 -211.341716)
		(width 0.101854)
		(layer "F.Cu")
		(net "M_C_CPU1_SB_DQ<19>")
	)
	(segment
		(start 93.784166 -231.436164)
		(end 93.784166 -230.900478)
		(width 0.20066)
		(layer "F.Cu")
		(net "M_C_CPU1_SB_DQ<19>")
	)
	(segment
		(start 33.401762 -211.124292)
		(end 33.848294 -211.124292)
		(width 0.20066)
		(layer "F.Cu")
		(net "M_C_CPU1_SB_DQ<19>")
	)
	(segment
		(start 32.794702 -210.912456)
		(end 33.189926 -210.912456)
		(width 0.20066)
		(layer "F.Cu")
		(net "M_C_CPU1_SB_DQ<19>")
	)
	(segment
		(start 29.899864 -211.341716)
		(end 31.972758 -211.341716)
		(width 0.1016)
		(layer "F.Cu")
		(net "M_C_CPU1_SB_DQ<19>")
	)
	(segment
		(start 34.055812 -210.916774)
		(end 34.871914 -210.916774)
		(width 0.20066)
		(layer "F.Cu")
		(net "M_C_CPU1_SB_DQ<19>")
	)
	(segment
		(start 27.328114 -210.916774)
		(end 29.025342 -210.916774)
		(width 0.20066)
		(layer "F.Cu")
		(net "M_C_CPU1_SB_DQ<19>")
	)
	(segment
		(start 35.976814 -210.916774)
		(end 34.871914 -210.916774)
		(width 0.20066)
		(layer "F.Cu")
		(net "M_C_CPU1_SB_DQ<19>")
	)
	(segment
		(start 29.151326 -211.042758)
		(end 29.151326 -211.213446)
		(width 0.20066)
		(layer "F.Cu")
		(net "M_C_CPU1_SB_DQ<19>")
	)
	(segment
		(start 31.972758 -211.341716)
		(end 32.51708 -211.341716)
		(width 0.20066)
		(layer "F.Cu")
		(net "M_C_CPU1_SB_DQ<19>")
	)
	(segment
		(start 33.848294 -211.124292)
		(end 34.055812 -210.916774)
		(width 0.20066)
		(layer "F.Cu")
		(net "M_C_CPU1_SB_DQ<19>")
	)
	(segment
		(start 29.29382 -211.35594)
		(end 29.647642 -211.35594)
		(width 0.20066)
		(layer "F.Cu")
		(net "M_C_CPU1_SB_DQ<19>")
	)
	(segment
		(start 93.783912 -231.436418)
		(end 93.784166 -231.436164)
		(width 0.20066)
		(layer "F.Cu")
		(net "M_C_CPU1_SB_DQ<19>")
	)
	(segment
		(start 32.51708 -211.341716)
		(end 32.666178 -211.192618)
		(width 0.20066)
		(layer "F.Cu")
		(net "M_C_CPU1_SB_DQ<19>")
	)
	(segment
		(start 29.025342 -210.916774)
		(end 29.151326 -211.042758)
		(width 0.20066)
		(layer "F.Cu")
		(net "M_C_CPU1_SB_DQ<19>")
	)
	(segment
		(start 29.151326 -211.213446)
		(end 29.29382 -211.35594)
		(width 0.20066)
		(layer "F.Cu")
		(net "M_C_CPU1_SB_DQ<19>")
	)
	(segment
		(start 33.189926 -210.912456)
		(end 33.401762 -211.124292)
		(width 0.20066)
		(layer "F.Cu")
		(net "M_C_CPU1_SB_DQ<19>")
	)
	(segment
		(start 32.666178 -211.192618)
		(end 32.666178 -211.04098)
		(width 0.20066)
		(layer "F.Cu")
		(net "M_C_CPU1_SB_DQ<19>")
	)
	(segment
		(start 32.666178 -211.04098)
		(end 32.794702 -210.912456)
		(width 0.20066)
		(layer "F.Cu")
		(net "M_C_CPU1_SB_DQ<19>")
	)
	(segment
		(start 61.078872 -212.59673)
		(end 60.753752 -212.59673)
		(width 0.18288)
		(layer "In4.Cu")
		(net "M_C_CPU1_SB_DQ<19>")
	)
	(segment
		(start 43.449748 -212.435948)
		(end 43.048682 -212.435948)
		(width 0.18288)
		(layer "In4.Cu")
		(net "M_C_CPU1_SB_DQ<19>")
	)
	(segment
		(start 60.387992 -213.226142)
		(end 59.393582 -213.226142)
		(width 0.18288)
		(layer "In4.Cu")
		(net "M_C_CPU1_SB_DQ<19>")
	)
	(segment
		(start 39.99357 -212.421724)
		(end 39.09949 -211.527644)
		(width 0.18288)
		(layer "In4.Cu")
		(net "M_C_CPU1_SB_DQ<19>")
	)
	(segment
		(start 83.975702 -230.88727)
		(end 83.069938 -229.981506)
		(width 0.088646)
		(layer "In4.Cu")
		(net "M_C_CPU1_SB_DQ<19>")
	)
	(segment
		(start 92.662756 -230.572818)
		(end 92.651072 -230.579422)
		(width 0.088646)
		(layer "In4.Cu")
		(net "M_C_CPU1_SB_DQ<19>")
	)
	(segment
		(start 56.398668 -212.275674)
		(end 56.073548 -212.275674)
		(width 0.18288)
		(layer "In4.Cu")
		(net "M_C_CPU1_SB_DQ<19>")
	)
	(segment
		(start 37.815266 -210.919568)
		(end 37.815266 -211.344764)
		(width 0.18288)
		(layer "In4.Cu")
		(net "M_C_CPU1_SB_DQ<19>")
	)
	(segment
		(start 84.198968 -231.224836)
		(end 83.975702 -231.00157)
		(width 0.088646)
		(layer "In4.Cu")
		(net "M_C_CPU1_SB_DQ<19>")
	)
	(segment
		(start 59.1566 -212.98916)
		(end 58.146188 -212.98916)
		(width 0.18288)
		(layer "In4.Cu")
		(net "M_C_CPU1_SB_DQ<19>")
	)
	(segment
		(start 61.261752 -212.77961)
		(end 61.078872 -212.59673)
		(width 0.18288)
		(layer "In4.Cu")
		(net "M_C_CPU1_SB_DQ<19>")
	)
	(segment
		(start 88.897714 -231.22509)
		(end 88.893142 -231.222296)
		(width 0.088646)
		(layer "In4.Cu")
		(net "M_C_CPU1_SB_DQ<19>")
	)
	(segment
		(start 49.71796 -213.891622)
		(end 44.905422 -213.891622)
		(width 0.18288)
		(layer "In4.Cu")
		(net "M_C_CPU1_SB_DQ<19>")
	)
	(segment
		(start 70.082918 -222.715582)
		(end 66.942208 -215.13292)
		(width 0.18288)
		(layer "In4.Cu")
		(net "M_C_CPU1_SB_DQ<19>")
	)
	(segment
		(start 57.089548 -212.98916)
		(end 56.764428 -212.98916)
		(width 0.18288)
		(layer "In4.Cu")
		(net "M_C_CPU1_SB_DQ<19>")
	)
	(segment
		(start 51.76139 -213.041738)
		(end 50.567844 -213.041738)
		(width 0.18288)
		(layer "In4.Cu")
		(net "M_C_CPU1_SB_DQ<19>")
	)
	(segment
		(start 44.905422 -213.891622)
		(end 43.449748 -212.435948)
		(width 0.18288)
		(layer "In4.Cu")
		(net "M_C_CPU1_SB_DQ<19>")
	)
	(segment
		(start 51.90109 -213.181438)
		(end 51.76139 -213.041738)
		(width 0.18288)
		(layer "In4.Cu")
		(net "M_C_CPU1_SB_DQ<19>")
	)
	(segment
		(start 55.890668 -212.80628)
		(end 55.707788 -212.98916)
		(width 0.18288)
		(layer "In4.Cu")
		(net "M_C_CPU1_SB_DQ<19>")
	)
	(segment
		(start 56.581548 -212.458554)
		(end 56.398668 -212.275674)
		(width 0.18288)
		(layer "In4.Cu")
		(net "M_C_CPU1_SB_DQ<19>")
	)
	(segment
		(start 38.323266 -210.736688)
		(end 37.998146 -210.736688)
		(width 0.18288)
		(layer "In4.Cu")
		(net "M_C_CPU1_SB_DQ<19>")
	)
	(segment
		(start 54.859682 -213.181438)
		(end 51.90109 -213.181438)
		(width 0.18288)
		(layer "In4.Cu")
		(net "M_C_CPU1_SB_DQ<19>")
	)
	(segment
		(start 61.444632 -213.226142)
		(end 61.261752 -213.043262)
		(width 0.18288)
		(layer "In4.Cu")
		(net "M_C_CPU1_SB_DQ<19>")
	)
	(segment
		(start 37.998146 -210.736688)
		(end 37.815266 -210.919568)
		(width 0.18288)
		(layer "In4.Cu")
		(net "M_C_CPU1_SB_DQ<19>")
	)
	(segment
		(start 42.195242 -211.889848)
		(end 42.195242 -212.253322)
		(width 0.18288)
		(layer "In4.Cu")
		(net "M_C_CPU1_SB_DQ<19>")
	)
	(segment
		(start 59.393582 -213.226142)
		(end 59.1566 -212.98916)
		(width 0.18288)
		(layer "In4.Cu")
		(net "M_C_CPU1_SB_DQ<19>")
	)
	(segment
		(start 57.455308 -211.667598)
		(end 57.272428 -211.850478)
		(width 0.18288)
		(layer "In4.Cu")
		(net "M_C_CPU1_SB_DQ<19>")
	)
	(segment
		(start 91.385898 -231.012492)
		(end 91.24442 -231.15397)
		(width 0.088646)
		(layer "In4.Cu")
		(net "M_C_CPU1_SB_DQ<19>")
	)
	(segment
		(start 43.048682 -212.435948)
		(end 42.888662 -212.275928)
		(width 0.18288)
		(layer "In4.Cu")
		(net "M_C_CPU1_SB_DQ<19>")
	)
	(segment
		(start 37.815266 -211.344764)
		(end 37.632386 -211.527644)
		(width 0.18288)
		(layer "In4.Cu")
		(net "M_C_CPU1_SB_DQ<19>")
	)
	(segment
		(start 55.890668 -212.458554)
		(end 55.890668 -212.80628)
		(width 0.18288)
		(layer "In4.Cu")
		(net "M_C_CPU1_SB_DQ<19>")
	)
	(segment
		(start 66.942208 -215.13292)
		(end 65.925954 -214.116666)
		(width 0.18288)
		(layer "In4.Cu")
		(net "M_C_CPU1_SB_DQ<19>")
	)
	(segment
		(start 42.02684 -212.421724)
		(end 39.99357 -212.421724)
		(width 0.18288)
		(layer "In4.Cu")
		(net "M_C_CPU1_SB_DQ<19>")
	)
	(segment
		(start 83.069938 -229.981506)
		(end 82.708496 -229.981506)
		(width 0.088646)
		(layer "In4.Cu")
		(net "M_C_CPU1_SB_DQ<19>")
	)
	(segment
		(start 93.784166 -230.900478)
		(end 93.783912 -230.900478)
		(width 0.088646)
		(layer "In4.Cu")
		(net "M_C_CPU1_SB_DQ<19>")
	)
	(segment
		(start 77.348842 -229.981506)
		(end 70.082918 -222.715582)
		(width 0.18288)
		(layer "In4.Cu")
		(net "M_C_CPU1_SB_DQ<19>")
	)
	(segment
		(start 55.707788 -212.98916)
		(end 55.05196 -212.98916)
		(width 0.18288)
		(layer "In4.Cu")
		(net "M_C_CPU1_SB_DQ<19>")
	)
	(segment
		(start 55.05196 -212.98916)
		(end 54.859682 -213.181438)
		(width 0.18288)
		(layer "In4.Cu")
		(net "M_C_CPU1_SB_DQ<19>")
	)
	(segment
		(start 57.963308 -212.80628)
		(end 57.963308 -211.850478)
		(width 0.18288)
		(layer "In4.Cu")
		(net "M_C_CPU1_SB_DQ<19>")
	)
	(segment
		(start 57.272428 -211.850478)
		(end 57.272428 -212.80628)
		(width 0.18288)
		(layer "In4.Cu")
		(net "M_C_CPU1_SB_DQ<19>")
	)
	(segment
		(start 57.963308 -211.850478)
		(end 57.780428 -211.667598)
		(width 0.18288)
		(layer "In4.Cu")
		(net "M_C_CPU1_SB_DQ<19>")
	)
	(segment
		(start 42.728642 -211.704428)
		(end 42.380662 -211.704428)
		(width 0.18288)
		(layer "In4.Cu")
		(net "M_C_CPU1_SB_DQ<19>")
	)
	(segment
		(start 93.428312 -230.805228)
		(end 93.031564 -230.57612)
		(width 0.088646)
		(layer "In4.Cu")
		(net "M_C_CPU1_SB_DQ<19>")
	)
	(segment
		(start 56.581548 -212.80628)
		(end 56.581548 -212.458554)
		(width 0.18288)
		(layer "In4.Cu")
		(net "M_C_CPU1_SB_DQ<19>")
	)
	(segment
		(start 89.837514 -231.22509)
		(end 89.830148 -231.220772)
		(width 0.088646)
		(layer "In4.Cu")
		(net "M_C_CPU1_SB_DQ<19>")
	)
	(segment
		(start 90.781886 -231.22763)
		(end 90.777314 -231.22509)
		(width 0.088646)
		(layer "In4.Cu")
		(net "M_C_CPU1_SB_DQ<19>")
	)
	(segment
		(start 90.777314 -231.22509)
		(end 90.769948 -231.220772)
		(width 0.088646)
		(layer "In4.Cu")
		(net "M_C_CPU1_SB_DQ<19>")
	)
	(segment
		(start 42.195242 -212.253322)
		(end 42.02684 -212.421724)
		(width 0.18288)
		(layer "In4.Cu")
		(net "M_C_CPU1_SB_DQ<19>")
	)
	(segment
		(start 82.708496 -229.981506)
		(end 77.348842 -229.981506)
		(width 0.18288)
		(layer "In4.Cu")
		(net "M_C_CPU1_SB_DQ<19>")
	)
	(segment
		(start 65.925954 -214.116666)
		(end 63.842138 -214.116666)
		(width 0.18288)
		(layer "In4.Cu")
		(net "M_C_CPU1_SB_DQ<19>")
	)
	(segment
		(start 42.888662 -212.275928)
		(end 42.888662 -211.864448)
		(width 0.18288)
		(layer "In4.Cu")
		(net "M_C_CPU1_SB_DQ<19>")
	)
	(segment
		(start 56.073548 -212.275674)
		(end 55.890668 -212.458554)
		(width 0.18288)
		(layer "In4.Cu")
		(net "M_C_CPU1_SB_DQ<19>")
	)
	(segment
		(start 38.506146 -211.344764)
		(end 38.506146 -210.919568)
		(width 0.18288)
		(layer "In4.Cu")
		(net "M_C_CPU1_SB_DQ<19>")
	)
	(segment
		(start 91.722956 -230.572818)
		(end 91.711272 -230.579422)
		(width 0.088646)
		(layer "In4.Cu")
		(net "M_C_CPU1_SB_DQ<19>")
	)
	(segment
		(start 87.957914 -231.22509)
		(end 87.958168 -231.224836)
		(width 0.088646)
		(layer "In4.Cu")
		(net "M_C_CPU1_SB_DQ<19>")
	)
	(segment
		(start 56.764428 -212.98916)
		(end 56.581548 -212.80628)
		(width 0.18288)
		(layer "In4.Cu")
		(net "M_C_CPU1_SB_DQ<19>")
	)
	(segment
		(start 39.09949 -211.527644)
		(end 38.689026 -211.527644)
		(width 0.18288)
		(layer "In4.Cu")
		(net "M_C_CPU1_SB_DQ<19>")
	)
	(segment
		(start 57.780428 -211.667598)
		(end 57.455308 -211.667598)
		(width 0.18288)
		(layer "In4.Cu")
		(net "M_C_CPU1_SB_DQ<19>")
	)
	(segment
		(start 58.146188 -212.98916)
		(end 57.963308 -212.80628)
		(width 0.18288)
		(layer "In4.Cu")
		(net "M_C_CPU1_SB_DQ<19>")
	)
	(segment
		(start 61.261752 -213.043262)
		(end 61.261752 -212.77961)
		(width 0.18288)
		(layer "In4.Cu")
		(net "M_C_CPU1_SB_DQ<19>")
	)
	(segment
		(start 60.570872 -212.77961)
		(end 60.570872 -213.043262)
		(width 0.18288)
		(layer "In4.Cu")
		(net "M_C_CPU1_SB_DQ<19>")
	)
	(segment
		(start 89.842086 -231.22763)
		(end 89.837514 -231.22509)
		(width 0.088646)
		(layer "In4.Cu")
		(net "M_C_CPU1_SB_DQ<19>")
	)
	(segment
		(start 42.380662 -211.704428)
		(end 42.195242 -211.889848)
		(width 0.18288)
		(layer "In4.Cu")
		(net "M_C_CPU1_SB_DQ<19>")
	)
	(segment
		(start 60.753752 -212.59673)
		(end 60.570872 -212.77961)
		(width 0.18288)
		(layer "In4.Cu")
		(net "M_C_CPU1_SB_DQ<19>")
	)
	(segment
		(start 91.493086 -230.792274)
		(end 91.427808 -230.950008)
		(width 0.088646)
		(layer "In4.Cu")
		(net "M_C_CPU1_SB_DQ<19>")
	)
	(segment
		(start 42.888662 -211.864448)
		(end 42.728642 -211.704428)
		(width 0.18288)
		(layer "In4.Cu")
		(net "M_C_CPU1_SB_DQ<19>")
	)
	(segment
		(start 38.506146 -210.919568)
		(end 38.323266 -210.736688)
		(width 0.18288)
		(layer "In4.Cu")
		(net "M_C_CPU1_SB_DQ<19>")
	)
	(segment
		(start 37.632386 -211.527644)
		(end 36.587684 -211.527644)
		(width 0.18288)
		(layer "In4.Cu")
		(net "M_C_CPU1_SB_DQ<19>")
	)
	(segment
		(start 36.587684 -211.527644)
		(end 35.976814 -210.916774)
		(width 0.18288)
		(layer "In4.Cu")
		(net "M_C_CPU1_SB_DQ<19>")
	)
	(segment
		(start 83.975702 -231.00157)
		(end 83.975702 -230.88727)
		(width 0.088646)
		(layer "In4.Cu")
		(net "M_C_CPU1_SB_DQ<19>")
	)
	(segment
		(start 50.567844 -213.041738)
		(end 49.71796 -213.891622)
		(width 0.18288)
		(layer "In4.Cu")
		(net "M_C_CPU1_SB_DQ<19>")
	)
	(segment
		(start 57.272428 -212.80628)
		(end 57.089548 -212.98916)
		(width 0.18288)
		(layer "In4.Cu")
		(net "M_C_CPU1_SB_DQ<19>")
	)
	(segment
		(start 62.951614 -213.226142)
		(end 61.444632 -213.226142)
		(width 0.18288)
		(layer "In4.Cu")
		(net "M_C_CPU1_SB_DQ<19>")
	)
	(segment
		(start 38.689026 -211.527644)
		(end 38.506146 -211.344764)
		(width 0.18288)
		(layer "In4.Cu")
		(net "M_C_CPU1_SB_DQ<19>")
	)
	(segment
		(start 63.842138 -214.116666)
		(end 62.951614 -213.226142)
		(width 0.18288)
		(layer "In4.Cu")
		(net "M_C_CPU1_SB_DQ<19>")
	)
	(segment
		(start 88.902286 -231.22763)
		(end 88.897714 -231.22509)
		(width 0.088646)
		(layer "In4.Cu")
		(net "M_C_CPU1_SB_DQ<19>")
	)
	(segment
		(start 60.570872 -213.043262)
		(end 60.387992 -213.226142)
		(width 0.18288)
		(layer "In4.Cu")
		(net "M_C_CPU1_SB_DQ<19>")
	)
	(arc
		(start 91.24442 -231.15397)
		(mid 91.200533 -231.192575)
		(end 91.151964 -231.22509)
		(width 0.088646)
		(layer "In4.Cu")
		(net "M_C_CPU1_SB_DQ<19>")
	)
	(arc
		(start 91.711272 -230.579422)
		(mid 91.629358 -230.63411)
		(end 91.555316 -230.699056)
		(width 0.088646)
		(layer "In4.Cu")
		(net "M_C_CPU1_SB_DQ<19>")
	)
	(arc
		(start 87.392764 -231.224836)
		(mid 87.205566 -231.274979)
		(end 87.018368 -231.224836)
		(width 0.088646)
		(layer "In4.Cu")
		(net "M_C_CPU1_SB_DQ<19>")
	)
	(arc
		(start 90.769948 -231.220772)
		(mid 90.490487 -231.149335)
		(end 90.212164 -231.22509)
		(width 0.088646)
		(layer "In4.Cu")
		(net "M_C_CPU1_SB_DQ<19>")
	)
	(arc
		(start 84.573364 -231.224836)
		(mid 84.386166 -231.274979)
		(end 84.198968 -231.224836)
		(width 0.088646)
		(layer "In4.Cu")
		(net "M_C_CPU1_SB_DQ<19>")
	)
	(arc
		(start 88.893142 -231.222296)
		(mid 88.612478 -231.149288)
		(end 88.332564 -231.22509)
		(width 0.088646)
		(layer "In4.Cu")
		(net "M_C_CPU1_SB_DQ<19>")
	)
	(arc
		(start 86.078568 -231.224836)
		(mid 85.795866 -231.149094)
		(end 85.513164 -231.224836)
		(width 0.088646)
		(layer "In4.Cu")
		(net "M_C_CPU1_SB_DQ<19>")
	)
	(arc
		(start 93.031564 -230.57612)
		(mid 92.84761 -230.525991)
		(end 92.662756 -230.572818)
		(width 0.088646)
		(layer "In4.Cu")
		(net "M_C_CPU1_SB_DQ<19>")
	)
	(arc
		(start 87.018368 -231.224836)
		(mid 86.735666 -231.149094)
		(end 86.452964 -231.224836)
		(width 0.088646)
		(layer "In4.Cu")
		(net "M_C_CPU1_SB_DQ<19>")
	)
	(arc
		(start 92.651072 -230.579422)
		(mid 92.370967 -230.651864)
		(end 92.091764 -230.57612)
		(width 0.088646)
		(layer "In4.Cu")
		(net "M_C_CPU1_SB_DQ<19>")
	)
	(arc
		(start 85.138768 -231.224836)
		(mid 84.856066 -231.149094)
		(end 84.573364 -231.224836)
		(width 0.088646)
		(layer "In4.Cu")
		(net "M_C_CPU1_SB_DQ<19>")
	)
	(arc
		(start 92.091764 -230.57612)
		(mid 91.90781 -230.525991)
		(end 91.722956 -230.572818)
		(width 0.088646)
		(layer "In4.Cu")
		(net "M_C_CPU1_SB_DQ<19>")
	)
	(arc
		(start 90.212164 -231.22509)
		(mid 90.02747 -231.275191)
		(end 89.842086 -231.22763)
		(width 0.088646)
		(layer "In4.Cu")
		(net "M_C_CPU1_SB_DQ<19>")
	)
	(arc
		(start 89.830148 -231.220772)
		(mid 89.550687 -231.149335)
		(end 89.272364 -231.22509)
		(width 0.088646)
		(layer "In4.Cu")
		(net "M_C_CPU1_SB_DQ<19>")
	)
	(arc
		(start 91.151964 -231.22509)
		(mid 90.96727 -231.275191)
		(end 90.781886 -231.22763)
		(width 0.088646)
		(layer "In4.Cu")
		(net "M_C_CPU1_SB_DQ<19>")
	)
	(arc
		(start 86.452964 -231.224836)
		(mid 86.265766 -231.274979)
		(end 86.078568 -231.224836)
		(width 0.088646)
		(layer "In4.Cu")
		(net "M_C_CPU1_SB_DQ<19>")
	)
	(arc
		(start 88.332564 -231.22509)
		(mid 88.145256 -231.275199)
		(end 87.957914 -231.22509)
		(width 0.088646)
		(layer "In4.Cu")
		(net "M_C_CPU1_SB_DQ<19>")
	)
	(arc
		(start 91.427808 -230.950008)
		(mid 91.409924 -230.983309)
		(end 91.385898 -231.012492)
		(width 0.088646)
		(layer "In4.Cu")
		(net "M_C_CPU1_SB_DQ<19>")
	)
	(arc
		(start 87.958168 -231.224836)
		(mid 87.675466 -231.149094)
		(end 87.392764 -231.224836)
		(width 0.088646)
		(layer "In4.Cu")
		(net "M_C_CPU1_SB_DQ<19>")
	)
	(arc
		(start 93.783912 -230.900478)
		(mid 93.599827 -230.8763)
		(end 93.428312 -230.805228)
		(width 0.088646)
		(layer "In4.Cu")
		(net "M_C_CPU1_SB_DQ<19>")
	)
	(arc
		(start 91.555316 -230.699056)
		(mid 91.519622 -230.742606)
		(end 91.493086 -230.792274)
		(width 0.088646)
		(layer "In4.Cu")
		(net "M_C_CPU1_SB_DQ<19>")
	)
	(arc
		(start 89.272364 -231.22509)
		(mid 89.08767 -231.275191)
		(end 88.902286 -231.22763)
		(width 0.088646)
		(layer "In4.Cu")
		(net "M_C_CPU1_SB_DQ<19>")
	)
	(arc
		(start 85.513164 -231.224836)
		(mid 85.325966 -231.274979)
		(end 85.138768 -231.224836)
		(width 0.088646)
		(layer "In4.Cu")
		(net "M_C_CPU1_SB_DQ<19>")
	)
	(segment
		(start 33.55721 -212.616796)
		(end 34.871914 -212.616796)
		(width 0.20066)
		(layer "F.Cu")
		(net "M_C_CPU1_SB_DQ<18>")
	)
	(segment
		(start 32.605726 -212.191854)
		(end 32.74949 -212.335618)
		(width 0.20066)
		(layer "F.Cu")
		(net "M_C_CPU1_SB_DQ<18>")
	)
	(segment
		(start 32.74949 -212.335618)
		(end 32.74949 -212.661246)
		(width 0.20066)
		(layer "F.Cu")
		(net "M_C_CPU1_SB_DQ<18>")
	)
	(segment
		(start 28.475178 -212.616796)
		(end 28.91028 -212.181694)
		(width 0.20066)
		(layer "F.Cu")
		(net "M_C_CPU1_SB_DQ<18>")
	)
	(segment
		(start 93.314266 -232.250488)
		(end 93.314012 -232.250234)
		(width 0.20066)
		(layer "F.Cu")
		(net "M_C_CPU1_SB_DQ<18>")
	)
	(segment
		(start 29.657802 -212.191854)
		(end 29.912818 -212.191854)
		(width 0.101854)
		(layer "F.Cu")
		(net "M_C_CPU1_SB_DQ<18>")
	)
	(segment
		(start 29.647642 -212.181694)
		(end 29.657802 -212.191854)
		(width 0.101854)
		(layer "F.Cu")
		(net "M_C_CPU1_SB_DQ<18>")
	)
	(segment
		(start 27.328114 -212.616796)
		(end 28.475178 -212.616796)
		(width 0.20066)
		(layer "F.Cu")
		(net "M_C_CPU1_SB_DQ<18>")
	)
	(segment
		(start 32.916876 -212.828632)
		(end 33.345374 -212.828632)
		(width 0.20066)
		(layer "F.Cu")
		(net "M_C_CPU1_SB_DQ<18>")
	)
	(segment
		(start 29.912818 -212.191854)
		(end 31.972758 -212.191854)
		(width 0.1016)
		(layer "F.Cu")
		(net "M_C_CPU1_SB_DQ<18>")
	)
	(segment
		(start 31.972758 -212.191854)
		(end 32.605726 -212.191854)
		(width 0.20066)
		(layer "F.Cu")
		(net "M_C_CPU1_SB_DQ<18>")
	)
	(segment
		(start 93.314012 -232.250234)
		(end 93.314012 -231.714548)
		(width 0.20066)
		(layer "F.Cu")
		(net "M_C_CPU1_SB_DQ<18>")
	)
	(segment
		(start 35.976814 -212.616796)
		(end 34.871914 -212.616796)
		(width 0.20066)
		(layer "F.Cu")
		(net "M_C_CPU1_SB_DQ<18>")
	)
	(segment
		(start 32.74949 -212.661246)
		(end 32.916876 -212.828632)
		(width 0.20066)
		(layer "F.Cu")
		(net "M_C_CPU1_SB_DQ<18>")
	)
	(segment
		(start 33.345374 -212.828632)
		(end 33.55721 -212.616796)
		(width 0.20066)
		(layer "F.Cu")
		(net "M_C_CPU1_SB_DQ<18>")
	)
	(segment
		(start 28.91028 -212.181694)
		(end 29.647642 -212.181694)
		(width 0.20066)
		(layer "F.Cu")
		(net "M_C_CPU1_SB_DQ<18>")
	)
	(segment
		(start 93.314012 -231.714548)
		(end 93.314012 -231.714294)
		(width 0.088646)
		(layer "In4.Cu")
		(net "M_C_CPU1_SB_DQ<18>")
	)
	(segment
		(start 42.51579 -213.819994)
		(end 42.257218 -213.819994)
		(width 0.18288)
		(layer "In4.Cu")
		(net "M_C_CPU1_SB_DQ<18>")
	)
	(segment
		(start 85.057996 -232.03027)
		(end 85.043264 -232.038906)
		(width 0.088646)
		(layer "In4.Cu")
		(net "M_C_CPU1_SB_DQ<18>")
	)
	(segment
		(start 82.708496 -230.98506)
		(end 76.919074 -230.98506)
		(width 0.18288)
		(layer "In4.Cu")
		(net "M_C_CPU1_SB_DQ<18>")
	)
	(segment
		(start 53.698648 -214.490046)
		(end 53.515768 -214.307166)
		(width 0.18288)
		(layer "In4.Cu")
		(net "M_C_CPU1_SB_DQ<18>")
	)
	(segment
		(start 44.64177 -215.279732)
		(end 44.262802 -215.279732)
		(width 0.18288)
		(layer "In4.Cu")
		(net "M_C_CPU1_SB_DQ<18>")
	)
	(segment
		(start 52.08651 -215.06688)
		(end 51.76139 -214.74176)
		(width 0.18288)
		(layer "In4.Cu")
		(net "M_C_CPU1_SB_DQ<18>")
	)
	(segment
		(start 90.687906 -232.03535)
		(end 90.682064 -232.038906)
		(width 0.088646)
		(layer "In4.Cu")
		(net "M_C_CPU1_SB_DQ<18>")
	)
	(segment
		(start 84.118196 -232.03027)
		(end 84.0105 -232.03027)
		(width 0.088646)
		(layer "In4.Cu")
		(net "M_C_CPU1_SB_DQ<18>")
	)
	(segment
		(start 50.5333 -214.74176)
		(end 49.683416 -215.591644)
		(width 0.18288)
		(layer "In4.Cu")
		(net "M_C_CPU1_SB_DQ<18>")
	)
	(segment
		(start 56.820054 -214.50808)
		(end 55.343552 -214.50808)
		(width 0.18288)
		(layer "In4.Cu")
		(net "M_C_CPU1_SB_DQ<18>")
	)
	(segment
		(start 89.742264 -232.038906)
		(end 89.736422 -232.042208)
		(width 0.088646)
		(layer "In4.Cu")
		(net "M_C_CPU1_SB_DQ<18>")
	)
	(segment
		(start 90.682064 -232.038906)
		(end 90.676222 -232.042208)
		(width 0.088646)
		(layer "In4.Cu")
		(net "M_C_CPU1_SB_DQ<18>")
	)
	(segment
		(start 36.604702 -213.244684)
		(end 35.976814 -212.616796)
		(width 0.18288)
		(layer "In4.Cu")
		(net "M_C_CPU1_SB_DQ<18>")
	)
	(segment
		(start 42.745914 -214.050118)
		(end 42.51579 -213.819994)
		(width 0.18288)
		(layer "In4.Cu")
		(net "M_C_CPU1_SB_DQ<18>")
	)
	(segment
		(start 51.76139 -214.74176)
		(end 50.5333 -214.74176)
		(width 0.18288)
		(layer "In4.Cu")
		(net "M_C_CPU1_SB_DQ<18>")
	)
	(segment
		(start 57.002934 -215.02878)
		(end 57.002934 -214.69096)
		(width 0.18288)
		(layer "In4.Cu")
		(net "M_C_CPU1_SB_DQ<18>")
	)
	(segment
		(start 45.33265 -215.591644)
		(end 44.953682 -215.591644)
		(width 0.18288)
		(layer "In4.Cu")
		(net "M_C_CPU1_SB_DQ<18>")
	)
	(segment
		(start 89.748106 -232.03535)
		(end 89.742264 -232.038906)
		(width 0.088646)
		(layer "In4.Cu")
		(net "M_C_CPU1_SB_DQ<18>")
	)
	(segment
		(start 60.839604 -214.31123)
		(end 60.656724 -214.49411)
		(width 0.18288)
		(layer "In4.Cu")
		(net "M_C_CPU1_SB_DQ<18>")
	)
	(segment
		(start 58.726324 -214.50808)
		(end 57.876694 -214.50808)
		(width 0.18288)
		(layer "In4.Cu")
		(net "M_C_CPU1_SB_DQ<18>")
	)
	(segment
		(start 41.731692 -214.34552)
		(end 41.47312 -214.34552)
		(width 0.18288)
		(layer "In4.Cu")
		(net "M_C_CPU1_SB_DQ<18>")
	)
	(segment
		(start 64.300862 -215.685878)
		(end 63.332106 -215.685878)
		(width 0.18288)
		(layer "In4.Cu")
		(net "M_C_CPU1_SB_DQ<18>")
	)
	(segment
		(start 53.007768 -214.884)
		(end 52.824888 -215.06688)
		(width 0.18288)
		(layer "In4.Cu")
		(net "M_C_CPU1_SB_DQ<18>")
	)
	(segment
		(start 57.693814 -214.69096)
		(end 57.693814 -215.02878)
		(width 0.18288)
		(layer "In4.Cu")
		(net "M_C_CPU1_SB_DQ<18>")
	)
	(segment
		(start 76.919074 -230.98506)
		(end 69.255894 -223.32188)
		(width 0.18288)
		(layer "In4.Cu")
		(net "M_C_CPU1_SB_DQ<18>")
	)
	(segment
		(start 64.918844 -215.771984)
		(end 64.782192 -215.908636)
		(width 0.18288)
		(layer "In4.Cu")
		(net "M_C_CPU1_SB_DQ<18>")
	)
	(segment
		(start 41.47312 -214.34552)
		(end 40.979852 -213.852252)
		(width 0.18288)
		(layer "In4.Cu")
		(net "M_C_CPU1_SB_DQ<18>")
	)
	(segment
		(start 91.626944 -232.036112)
		(end 91.621864 -232.038906)
		(width 0.088646)
		(layer "In4.Cu")
		(net "M_C_CPU1_SB_DQ<18>")
	)
	(segment
		(start 54.784752 -215.06688)
		(end 53.881528 -215.06688)
		(width 0.18288)
		(layer "In4.Cu")
		(net "M_C_CPU1_SB_DQ<18>")
	)
	(segment
		(start 49.683416 -215.591644)
		(end 46.335442 -215.591644)
		(width 0.18288)
		(layer "In4.Cu")
		(net "M_C_CPU1_SB_DQ<18>")
	)
	(segment
		(start 67.360038 -218.745054)
		(end 65.270888 -216.655904)
		(width 0.18288)
		(layer "In4.Cu")
		(net "M_C_CPU1_SB_DQ<18>")
	)
	(segment
		(start 88.808306 -232.03535)
		(end 88.802464 -232.038906)
		(width 0.088646)
		(layer "In4.Cu")
		(net "M_C_CPU1_SB_DQ<18>")
	)
	(segment
		(start 61.347604 -214.691722)
		(end 61.347604 -214.49411)
		(width 0.18288)
		(layer "In4.Cu")
		(net "M_C_CPU1_SB_DQ<18>")
	)
	(segment
		(start 84.0105 -232.03027)
		(end 82.96529 -230.98506)
		(width 0.088646)
		(layer "In4.Cu")
		(net "M_C_CPU1_SB_DQ<18>")
	)
	(segment
		(start 91.809316 -231.70642)
		(end 91.809316 -231.714548)
		(width 0.088646)
		(layer "In4.Cu")
		(net "M_C_CPU1_SB_DQ<18>")
	)
	(segment
		(start 64.782192 -215.908636)
		(end 64.52362 -215.908636)
		(width 0.18288)
		(layer "In4.Cu")
		(net "M_C_CPU1_SB_DQ<18>")
	)
	(segment
		(start 65.177416 -215.771984)
		(end 64.918844 -215.771984)
		(width 0.18288)
		(layer "In4.Cu")
		(net "M_C_CPU1_SB_DQ<18>")
	)
	(segment
		(start 40.979852 -213.852252)
		(end 38.797484 -213.852252)
		(width 0.18288)
		(layer "In4.Cu")
		(net "M_C_CPU1_SB_DQ<18>")
	)
	(segment
		(start 42.745914 -214.30869)
		(end 42.745914 -214.050118)
		(width 0.18288)
		(layer "In4.Cu")
		(net "M_C_CPU1_SB_DQ<18>")
	)
	(segment
		(start 38.189916 -213.244684)
		(end 36.604702 -213.244684)
		(width 0.18288)
		(layer "In4.Cu")
		(net "M_C_CPU1_SB_DQ<18>")
	)
	(segment
		(start 91.621864 -232.038906)
		(end 91.616022 -232.042208)
		(width 0.088646)
		(layer "In4.Cu")
		(net "M_C_CPU1_SB_DQ<18>")
	)
	(segment
		(start 42.220388 -214.834216)
		(end 42.745914 -214.30869)
		(width 0.18288)
		(layer "In4.Cu")
		(net "M_C_CPU1_SB_DQ<18>")
	)
	(segment
		(start 44.262802 -215.279732)
		(end 43.95089 -215.591644)
		(width 0.18288)
		(layer "In4.Cu")
		(net "M_C_CPU1_SB_DQ<18>")
	)
	(segment
		(start 62.52083 -214.874602)
		(end 61.530484 -214.874602)
		(width 0.18288)
		(layer "In4.Cu")
		(net "M_C_CPU1_SB_DQ<18>")
	)
	(segment
		(start 82.96529 -230.98506)
		(end 82.708496 -230.98506)
		(width 0.088646)
		(layer "In4.Cu")
		(net "M_C_CPU1_SB_DQ<18>")
	)
	(segment
		(start 45.644562 -215.279732)
		(end 45.33265 -215.591644)
		(width 0.18288)
		(layer "In4.Cu")
		(net "M_C_CPU1_SB_DQ<18>")
	)
	(segment
		(start 65.40754 -216.26068)
		(end 65.40754 -216.002108)
		(width 0.18288)
		(layer "In4.Cu")
		(net "M_C_CPU1_SB_DQ<18>")
	)
	(segment
		(start 46.335442 -215.591644)
		(end 46.02353 -215.279732)
		(width 0.18288)
		(layer "In4.Cu")
		(net "M_C_CPU1_SB_DQ<18>")
	)
	(segment
		(start 57.693814 -215.02878)
		(end 57.510934 -215.21166)
		(width 0.18288)
		(layer "In4.Cu")
		(net "M_C_CPU1_SB_DQ<18>")
	)
	(segment
		(start 60.656724 -214.49411)
		(end 60.656724 -214.691722)
		(width 0.18288)
		(layer "In4.Cu")
		(net "M_C_CPU1_SB_DQ<18>")
	)
	(segment
		(start 42.719244 -215.591644)
		(end 42.220388 -215.092788)
		(width 0.18288)
		(layer "In4.Cu")
		(net "M_C_CPU1_SB_DQ<18>")
	)
	(segment
		(start 46.02353 -215.279732)
		(end 45.644562 -215.279732)
		(width 0.18288)
		(layer "In4.Cu")
		(net "M_C_CPU1_SB_DQ<18>")
	)
	(segment
		(start 53.881528 -215.06688)
		(end 53.698648 -214.884)
		(width 0.18288)
		(layer "In4.Cu")
		(net "M_C_CPU1_SB_DQ<18>")
	)
	(segment
		(start 53.515768 -214.307166)
		(end 53.190648 -214.307166)
		(width 0.18288)
		(layer "In4.Cu")
		(net "M_C_CPU1_SB_DQ<18>")
	)
	(segment
		(start 55.343552 -214.50808)
		(end 54.784752 -215.06688)
		(width 0.18288)
		(layer "In4.Cu")
		(net "M_C_CPU1_SB_DQ<18>")
	)
	(segment
		(start 65.40754 -216.002108)
		(end 65.177416 -215.771984)
		(width 0.18288)
		(layer "In4.Cu")
		(net "M_C_CPU1_SB_DQ<18>")
	)
	(segment
		(start 60.656724 -214.691722)
		(end 60.473844 -214.874602)
		(width 0.18288)
		(layer "In4.Cu")
		(net "M_C_CPU1_SB_DQ<18>")
	)
	(segment
		(start 57.510934 -215.21166)
		(end 57.185814 -215.21166)
		(width 0.18288)
		(layer "In4.Cu")
		(net "M_C_CPU1_SB_DQ<18>")
	)
	(segment
		(start 92.329508 -231.26827)
		(end 92.19184 -231.26827)
		(width 0.088646)
		(layer "In4.Cu")
		(net "M_C_CPU1_SB_DQ<18>")
	)
	(segment
		(start 42.257218 -213.819994)
		(end 41.731692 -214.34552)
		(width 0.18288)
		(layer "In4.Cu")
		(net "M_C_CPU1_SB_DQ<18>")
	)
	(segment
		(start 42.220388 -215.092788)
		(end 42.220388 -214.834216)
		(width 0.18288)
		(layer "In4.Cu")
		(net "M_C_CPU1_SB_DQ<18>")
	)
	(segment
		(start 57.185814 -215.21166)
		(end 57.002934 -215.02878)
		(width 0.18288)
		(layer "In4.Cu")
		(net "M_C_CPU1_SB_DQ<18>")
	)
	(segment
		(start 88.802464 -232.038906)
		(end 88.798654 -232.040938)
		(width 0.088646)
		(layer "In4.Cu")
		(net "M_C_CPU1_SB_DQ<18>")
	)
	(segment
		(start 93.314012 -231.714294)
		(end 93.248734 -231.649016)
		(width 0.088646)
		(layer "In4.Cu")
		(net "M_C_CPU1_SB_DQ<18>")
	)
	(segment
		(start 53.190648 -214.307166)
		(end 53.007768 -214.490046)
		(width 0.18288)
		(layer "In4.Cu")
		(net "M_C_CPU1_SB_DQ<18>")
	)
	(segment
		(start 53.007768 -214.490046)
		(end 53.007768 -214.884)
		(width 0.18288)
		(layer "In4.Cu")
		(net "M_C_CPU1_SB_DQ<18>")
	)
	(segment
		(start 61.347604 -214.49411)
		(end 61.164724 -214.31123)
		(width 0.18288)
		(layer "In4.Cu")
		(net "M_C_CPU1_SB_DQ<18>")
	)
	(segment
		(start 53.698648 -214.884)
		(end 53.698648 -214.490046)
		(width 0.18288)
		(layer "In4.Cu")
		(net "M_C_CPU1_SB_DQ<18>")
	)
	(segment
		(start 61.530484 -214.874602)
		(end 61.347604 -214.691722)
		(width 0.18288)
		(layer "In4.Cu")
		(net "M_C_CPU1_SB_DQ<18>")
	)
	(segment
		(start 65.270888 -216.655904)
		(end 65.270888 -216.397332)
		(width 0.18288)
		(layer "In4.Cu")
		(net "M_C_CPU1_SB_DQ<18>")
	)
	(segment
		(start 44.953682 -215.591644)
		(end 44.64177 -215.279732)
		(width 0.18288)
		(layer "In4.Cu")
		(net "M_C_CPU1_SB_DQ<18>")
	)
	(segment
		(start 69.255894 -223.32188)
		(end 67.360038 -218.745054)
		(width 0.18288)
		(layer "In4.Cu")
		(net "M_C_CPU1_SB_DQ<18>")
	)
	(segment
		(start 57.002934 -214.69096)
		(end 56.820054 -214.50808)
		(width 0.18288)
		(layer "In4.Cu")
		(net "M_C_CPU1_SB_DQ<18>")
	)
	(segment
		(start 43.95089 -215.591644)
		(end 42.719244 -215.591644)
		(width 0.18288)
		(layer "In4.Cu")
		(net "M_C_CPU1_SB_DQ<18>")
	)
	(segment
		(start 63.332106 -215.685878)
		(end 62.52083 -214.874602)
		(width 0.18288)
		(layer "In4.Cu")
		(net "M_C_CPU1_SB_DQ<18>")
	)
	(segment
		(start 64.52362 -215.908636)
		(end 64.300862 -215.685878)
		(width 0.18288)
		(layer "In4.Cu")
		(net "M_C_CPU1_SB_DQ<18>")
	)
	(segment
		(start 38.797484 -213.852252)
		(end 38.189916 -213.244684)
		(width 0.18288)
		(layer "In4.Cu")
		(net "M_C_CPU1_SB_DQ<18>")
	)
	(segment
		(start 59.092846 -214.874602)
		(end 58.726324 -214.50808)
		(width 0.18288)
		(layer "In4.Cu")
		(net "M_C_CPU1_SB_DQ<18>")
	)
	(segment
		(start 65.270888 -216.397332)
		(end 65.40754 -216.26068)
		(width 0.18288)
		(layer "In4.Cu")
		(net "M_C_CPU1_SB_DQ<18>")
	)
	(segment
		(start 52.824888 -215.06688)
		(end 52.08651 -215.06688)
		(width 0.18288)
		(layer "In4.Cu")
		(net "M_C_CPU1_SB_DQ<18>")
	)
	(segment
		(start 61.164724 -214.31123)
		(end 60.839604 -214.31123)
		(width 0.18288)
		(layer "In4.Cu")
		(net "M_C_CPU1_SB_DQ<18>")
	)
	(segment
		(start 60.473844 -214.874602)
		(end 59.092846 -214.874602)
		(width 0.18288)
		(layer "In4.Cu")
		(net "M_C_CPU1_SB_DQ<18>")
	)
	(segment
		(start 57.876694 -214.50808)
		(end 57.693814 -214.69096)
		(width 0.18288)
		(layer "In4.Cu")
		(net "M_C_CPU1_SB_DQ<18>")
	)
	(arc
		(start 88.798654 -232.040938)
		(mid 88.612964 -232.089048)
		(end 88.427814 -232.038906)
		(width 0.088646)
		(layer "In4.Cu")
		(net "M_C_CPU1_SB_DQ<18>")
	)
	(arc
		(start 90.307414 -232.038906)
		(mid 90.02824 -231.963141)
		(end 89.748106 -232.03535)
		(width 0.088646)
		(layer "In4.Cu")
		(net "M_C_CPU1_SB_DQ<18>")
	)
	(arc
		(start 85.043264 -232.038906)
		(mid 84.856066 -232.089049)
		(end 84.668868 -232.038906)
		(width 0.088646)
		(layer "In4.Cu")
		(net "M_C_CPU1_SB_DQ<18>")
	)
	(arc
		(start 85.983064 -232.038906)
		(mid 85.795866 -232.089049)
		(end 85.608668 -232.038906)
		(width 0.088646)
		(layer "In4.Cu")
		(net "M_C_CPU1_SB_DQ<18>")
	)
	(arc
		(start 87.862664 -232.038906)
		(mid 87.675466 -232.089049)
		(end 87.488268 -232.038906)
		(width 0.088646)
		(layer "In4.Cu")
		(net "M_C_CPU1_SB_DQ<18>")
	)
	(arc
		(start 87.488268 -232.038906)
		(mid 87.205566 -231.96313)
		(end 86.922864 -232.038906)
		(width 0.088646)
		(layer "In4.Cu")
		(net "M_C_CPU1_SB_DQ<18>")
	)
	(arc
		(start 91.857068 -231.48671)
		(mid 91.82214 -231.594165)
		(end 91.809316 -231.70642)
		(width 0.088646)
		(layer "In4.Cu")
		(net "M_C_CPU1_SB_DQ<18>")
	)
	(arc
		(start 86.548468 -232.038906)
		(mid 86.265766 -231.96313)
		(end 85.983064 -232.038906)
		(width 0.088646)
		(layer "In4.Cu")
		(net "M_C_CPU1_SB_DQ<18>")
	)
	(arc
		(start 91.616022 -232.042208)
		(mid 91.431167 -232.089158)
		(end 91.247214 -232.038906)
		(width 0.088646)
		(layer "In4.Cu")
		(net "M_C_CPU1_SB_DQ<18>")
	)
	(arc
		(start 91.809316 -231.714548)
		(mid 91.760568 -231.899414)
		(end 91.626944 -232.036112)
		(width 0.088646)
		(layer "In4.Cu")
		(net "M_C_CPU1_SB_DQ<18>")
	)
	(arc
		(start 85.608668 -232.038906)
		(mid 85.334469 -231.963071)
		(end 85.057996 -232.03027)
		(width 0.088646)
		(layer "In4.Cu")
		(net "M_C_CPU1_SB_DQ<18>")
	)
	(arc
		(start 93.248734 -231.649016)
		(mid 92.82699 -231.367215)
		(end 92.329508 -231.26827)
		(width 0.088646)
		(layer "In4.Cu")
		(net "M_C_CPU1_SB_DQ<18>")
	)
	(arc
		(start 88.427814 -232.038906)
		(mid 88.145256 -231.963257)
		(end 87.862664 -232.038906)
		(width 0.088646)
		(layer "In4.Cu")
		(net "M_C_CPU1_SB_DQ<18>")
	)
	(arc
		(start 86.922864 -232.038906)
		(mid 86.735666 -232.089049)
		(end 86.548468 -232.038906)
		(width 0.088646)
		(layer "In4.Cu")
		(net "M_C_CPU1_SB_DQ<18>")
	)
	(arc
		(start 89.736422 -232.042208)
		(mid 89.551567 -232.089158)
		(end 89.367614 -232.038906)
		(width 0.088646)
		(layer "In4.Cu")
		(net "M_C_CPU1_SB_DQ<18>")
	)
	(arc
		(start 89.367614 -232.038906)
		(mid 89.08844 -231.963141)
		(end 88.808306 -232.03535)
		(width 0.088646)
		(layer "In4.Cu")
		(net "M_C_CPU1_SB_DQ<18>")
	)
	(arc
		(start 92.19184 -231.26827)
		(mid 91.991971 -231.327709)
		(end 91.857068 -231.48671)
		(width 0.088646)
		(layer "In4.Cu")
		(net "M_C_CPU1_SB_DQ<18>")
	)
	(arc
		(start 91.247214 -232.038906)
		(mid 90.96804 -231.963141)
		(end 90.687906 -232.03535)
		(width 0.088646)
		(layer "In4.Cu")
		(net "M_C_CPU1_SB_DQ<18>")
	)
	(arc
		(start 90.676222 -232.042208)
		(mid 90.491367 -232.089158)
		(end 90.307414 -232.038906)
		(width 0.088646)
		(layer "In4.Cu")
		(net "M_C_CPU1_SB_DQ<18>")
	)
	(arc
		(start 84.668868 -232.038906)
		(mid 84.394669 -231.963071)
		(end 84.118196 -232.03027)
		(width 0.088646)
		(layer "In4.Cu")
		(net "M_C_CPU1_SB_DQ<18>")
	)
	(segment
		(start 25.595072 -211.332826)
		(end 26.20391 -211.332826)
		(width 0.20066)
		(layer "F.Cu")
		(net "M_C_CPU1_SB_DQ<17>")
	)
	(segment
		(start 25.432512 -211.823554)
		(end 25.432512 -211.495386)
		(width 0.20066)
		(layer "F.Cu")
		(net "M_C_CPU1_SB_DQ<17>")
	)
	(segment
		(start 25.27808 -211.977986)
		(end 25.432512 -211.823554)
		(width 0.20066)
		(layer "F.Cu")
		(net "M_C_CPU1_SB_DQ<17>")
	)
	(segment
		(start 26.2128 -211.341716)
		(end 28.198318 -211.341716)
		(width 0.1016)
		(layer "F.Cu")
		(net "M_C_CPU1_SB_DQ<17>")
	)
	(segment
		(start 91.904312 -231.436418)
		(end 91.904566 -231.436164)
		(width 0.20066)
		(layer "F.Cu")
		(net "M_C_CPU1_SB_DQ<17>")
	)
	(segment
		(start 24.562308 -211.766658)
		(end 24.773636 -211.977986)
		(width 0.20066)
		(layer "F.Cu")
		(net "M_C_CPU1_SB_DQ<17>")
	)
	(segment
		(start 28.198318 -211.341716)
		(end 28.529026 -211.341716)
		(width 0.101854)
		(layer "F.Cu")
		(net "M_C_CPU1_SB_DQ<17>")
	)
	(segment
		(start 28.529026 -211.341716)
		(end 28.707588 -211.341716)
		(width 0.20066)
		(layer "F.Cu")
		(net "M_C_CPU1_SB_DQ<17>")
	)
	(segment
		(start 23.228046 -211.766658)
		(end 24.562308 -211.766658)
		(width 0.20066)
		(layer "F.Cu")
		(net "M_C_CPU1_SB_DQ<17>")
	)
	(segment
		(start 25.432512 -211.495386)
		(end 25.595072 -211.332826)
		(width 0.20066)
		(layer "F.Cu")
		(net "M_C_CPU1_SB_DQ<17>")
	)
	(segment
		(start 31.876746 -211.766658)
		(end 30.771846 -211.766658)
		(width 0.20066)
		(layer "F.Cu")
		(net "M_C_CPU1_SB_DQ<17>")
	)
	(segment
		(start 26.20391 -211.332826)
		(end 26.2128 -211.341716)
		(width 0.1016)
		(layer "F.Cu")
		(net "M_C_CPU1_SB_DQ<17>")
	)
	(segment
		(start 29.13253 -211.766658)
		(end 30.771846 -211.766658)
		(width 0.20066)
		(layer "F.Cu")
		(net "M_C_CPU1_SB_DQ<17>")
	)
	(segment
		(start 24.773636 -211.977986)
		(end 25.27808 -211.977986)
		(width 0.20066)
		(layer "F.Cu")
		(net "M_C_CPU1_SB_DQ<17>")
	)
	(segment
		(start 91.904566 -231.436164)
		(end 91.904566 -230.900478)
		(width 0.20066)
		(layer "F.Cu")
		(net "M_C_CPU1_SB_DQ<17>")
	)
	(segment
		(start 28.707588 -211.341716)
		(end 29.13253 -211.766658)
		(width 0.20066)
		(layer "F.Cu")
		(net "M_C_CPU1_SB_DQ<17>")
	)
	(segment
		(start 32.992822 -213.187788)
		(end 32.667702 -213.187788)
		(width 0.18288)
		(layer "In4.Cu")
		(net "M_C_CPU1_SB_DQ<17>")
	)
	(segment
		(start 58.940446 -213.81339)
		(end 58.771282 -213.982554)
		(width 0.18288)
		(layer "In4.Cu")
		(net "M_C_CPU1_SB_DQ<17>")
	)
	(segment
		(start 51.76139 -213.891876)
		(end 50.620422 -213.891876)
		(width 0.18288)
		(layer "In4.Cu")
		(net "M_C_CPU1_SB_DQ<17>")
	)
	(segment
		(start 35.227768 -212.191854)
		(end 35.044888 -212.374734)
		(width 0.18288)
		(layer "In4.Cu")
		(net "M_C_CPU1_SB_DQ<17>")
	)
	(segment
		(start 32.484822 -212.374734)
		(end 31.876746 -211.766658)
		(width 0.18288)
		(layer "In4.Cu")
		(net "M_C_CPU1_SB_DQ<17>")
	)
	(segment
		(start 35.044888 -212.374734)
		(end 35.044888 -213.16315)
		(width 0.18288)
		(layer "In4.Cu")
		(net "M_C_CPU1_SB_DQ<17>")
	)
	(segment
		(start 40.132508 -212.932518)
		(end 39.882572 -213.182454)
		(width 0.18288)
		(layer "In4.Cu")
		(net "M_C_CPU1_SB_DQ<17>")
	)
	(segment
		(start 39.882572 -213.182454)
		(end 39.150798 -213.182454)
		(width 0.18288)
		(layer "In4.Cu")
		(net "M_C_CPU1_SB_DQ<17>")
	)
	(segment
		(start 34.354008 -212.374734)
		(end 34.171128 -212.191854)
		(width 0.18288)
		(layer "In4.Cu")
		(net "M_C_CPU1_SB_DQ<17>")
	)
	(segment
		(start 67.174872 -216.996772)
		(end 64.802766 -214.624666)
		(width 0.18288)
		(layer "In4.Cu")
		(net "M_C_CPU1_SB_DQ<17>")
	)
	(segment
		(start 44.14266 -214.74176)
		(end 42.333418 -212.932518)
		(width 0.18288)
		(layer "In4.Cu")
		(net "M_C_CPU1_SB_DQ<17>")
	)
	(segment
		(start 34.536888 -213.34603)
		(end 34.354008 -213.16315)
		(width 0.18288)
		(layer "In4.Cu")
		(net "M_C_CPU1_SB_DQ<17>")
	)
	(segment
		(start 39.150798 -213.182454)
		(end 38.160198 -212.191854)
		(width 0.18288)
		(layer "In4.Cu")
		(net "M_C_CPU1_SB_DQ<17>")
	)
	(segment
		(start 77.143102 -230.479854)
		(end 69.660516 -222.997268)
		(width 0.18288)
		(layer "In4.Cu")
		(net "M_C_CPU1_SB_DQ<17>")
	)
	(segment
		(start 90.682064 -231.389936)
		(end 90.677492 -231.387396)
		(width 0.088646)
		(layer "In4.Cu")
		(net "M_C_CPU1_SB_DQ<17>")
	)
	(segment
		(start 88.802464 -231.389936)
		(end 88.798654 -231.387904)
		(width 0.088646)
		(layer "In4.Cu")
		(net "M_C_CPU1_SB_DQ<17>")
	)
	(segment
		(start 89.742264 -231.389936)
		(end 89.737692 -231.387396)
		(width 0.088646)
		(layer "In4.Cu")
		(net "M_C_CPU1_SB_DQ<17>")
	)
	(segment
		(start 62.746382 -213.81339)
		(end 58.940446 -213.81339)
		(width 0.18288)
		(layer "In4.Cu")
		(net "M_C_CPU1_SB_DQ<17>")
	)
	(segment
		(start 35.044888 -213.16315)
		(end 34.862008 -213.34603)
		(width 0.18288)
		(layer "In4.Cu")
		(net "M_C_CPU1_SB_DQ<17>")
	)
	(segment
		(start 83.977988 -231.299258)
		(end 83.158584 -230.479854)
		(width 0.088646)
		(layer "In4.Cu")
		(net "M_C_CPU1_SB_DQ<17>")
	)
	(segment
		(start 49.770538 -214.74176)
		(end 44.14266 -214.74176)
		(width 0.18288)
		(layer "In4.Cu")
		(net "M_C_CPU1_SB_DQ<17>")
	)
	(segment
		(start 42.333418 -212.932518)
		(end 40.132508 -212.932518)
		(width 0.18288)
		(layer "In4.Cu")
		(net "M_C_CPU1_SB_DQ<17>")
	)
	(segment
		(start 63.557658 -214.624666)
		(end 62.746382 -213.81339)
		(width 0.18288)
		(layer "In4.Cu")
		(net "M_C_CPU1_SB_DQ<17>")
	)
	(segment
		(start 64.802766 -214.624666)
		(end 63.557658 -214.624666)
		(width 0.18288)
		(layer "In4.Cu")
		(net "M_C_CPU1_SB_DQ<17>")
	)
	(segment
		(start 88.80983 -231.394254)
		(end 88.802464 -231.389936)
		(width 0.088646)
		(layer "In4.Cu")
		(net "M_C_CPU1_SB_DQ<17>")
	)
	(segment
		(start 87.862664 -231.389936)
		(end 87.862664 -231.39019)
		(width 0.088646)
		(layer "In4.Cu")
		(net "M_C_CPU1_SB_DQ<17>")
	)
	(segment
		(start 83.158584 -230.479854)
		(end 82.708496 -230.479854)
		(width 0.088646)
		(layer "In4.Cu")
		(net "M_C_CPU1_SB_DQ<17>")
	)
	(segment
		(start 90.68943 -231.394254)
		(end 90.682064 -231.389936)
		(width 0.088646)
		(layer "In4.Cu")
		(net "M_C_CPU1_SB_DQ<17>")
	)
	(segment
		(start 34.862008 -213.34603)
		(end 34.536888 -213.34603)
		(width 0.18288)
		(layer "In4.Cu")
		(net "M_C_CPU1_SB_DQ<17>")
	)
	(segment
		(start 69.660516 -222.997268)
		(end 67.174872 -216.996772)
		(width 0.18288)
		(layer "In4.Cu")
		(net "M_C_CPU1_SB_DQ<17>")
	)
	(segment
		(start 58.771282 -213.982554)
		(end 55.52186 -213.982554)
		(width 0.18288)
		(layer "In4.Cu")
		(net "M_C_CPU1_SB_DQ<17>")
	)
	(segment
		(start 55.52186 -213.982554)
		(end 55.317136 -213.77783)
		(width 0.18288)
		(layer "In4.Cu")
		(net "M_C_CPU1_SB_DQ<17>")
	)
	(segment
		(start 82.708496 -230.479854)
		(end 77.143102 -230.479854)
		(width 0.18288)
		(layer "In4.Cu")
		(net "M_C_CPU1_SB_DQ<17>")
	)
	(segment
		(start 33.175702 -212.374734)
		(end 33.175702 -213.004908)
		(width 0.18288)
		(layer "In4.Cu")
		(net "M_C_CPU1_SB_DQ<17>")
	)
	(segment
		(start 32.667702 -213.187788)
		(end 32.484822 -213.004908)
		(width 0.18288)
		(layer "In4.Cu")
		(net "M_C_CPU1_SB_DQ<17>")
	)
	(segment
		(start 32.484822 -213.004908)
		(end 32.484822 -212.374734)
		(width 0.18288)
		(layer "In4.Cu")
		(net "M_C_CPU1_SB_DQ<17>")
	)
	(segment
		(start 34.354008 -213.16315)
		(end 34.354008 -212.374734)
		(width 0.18288)
		(layer "In4.Cu")
		(net "M_C_CPU1_SB_DQ<17>")
	)
	(segment
		(start 34.171128 -212.191854)
		(end 33.358582 -212.191854)
		(width 0.18288)
		(layer "In4.Cu")
		(net "M_C_CPU1_SB_DQ<17>")
	)
	(segment
		(start 50.620422 -213.891876)
		(end 49.770538 -214.74176)
		(width 0.18288)
		(layer "In4.Cu")
		(net "M_C_CPU1_SB_DQ<17>")
	)
	(segment
		(start 91.32062 -231.347772)
		(end 91.247214 -231.389936)
		(width 0.088646)
		(layer "In4.Cu")
		(net "M_C_CPU1_SB_DQ<17>")
	)
	(segment
		(start 89.74963 -231.394254)
		(end 89.742264 -231.389936)
		(width 0.088646)
		(layer "In4.Cu")
		(net "M_C_CPU1_SB_DQ<17>")
	)
	(segment
		(start 38.160198 -212.191854)
		(end 35.227768 -212.191854)
		(width 0.18288)
		(layer "In4.Cu")
		(net "M_C_CPU1_SB_DQ<17>")
	)
	(segment
		(start 55.317136 -213.77783)
		(end 51.875436 -213.77783)
		(width 0.18288)
		(layer "In4.Cu")
		(net "M_C_CPU1_SB_DQ<17>")
	)
	(segment
		(start 33.175702 -213.004908)
		(end 32.992822 -213.187788)
		(width 0.18288)
		(layer "In4.Cu")
		(net "M_C_CPU1_SB_DQ<17>")
	)
	(segment
		(start 51.875436 -213.77783)
		(end 51.76139 -213.891876)
		(width 0.18288)
		(layer "In4.Cu")
		(net "M_C_CPU1_SB_DQ<17>")
	)
	(segment
		(start 33.358582 -212.191854)
		(end 33.175702 -212.374734)
		(width 0.18288)
		(layer "In4.Cu")
		(net "M_C_CPU1_SB_DQ<17>")
	)
	(arc
		(start 88.427814 -231.389936)
		(mid 88.145256 -231.465585)
		(end 87.862664 -231.389936)
		(width 0.088646)
		(layer "In4.Cu")
		(net "M_C_CPU1_SB_DQ<17>")
	)
	(arc
		(start 87.488268 -231.39019)
		(mid 87.205566 -231.465932)
		(end 86.922864 -231.39019)
		(width 0.088646)
		(layer "In4.Cu")
		(net "M_C_CPU1_SB_DQ<17>")
	)
	(arc
		(start 89.737692 -231.387396)
		(mid 89.552307 -231.339758)
		(end 89.367614 -231.389936)
		(width 0.088646)
		(layer "In4.Cu")
		(net "M_C_CPU1_SB_DQ<17>")
	)
	(arc
		(start 85.043264 -231.39019)
		(mid 84.856066 -231.340047)
		(end 84.668868 -231.39019)
		(width 0.088646)
		(layer "In4.Cu")
		(net "M_C_CPU1_SB_DQ<17>")
	)
	(arc
		(start 90.307414 -231.389936)
		(mid 90.029091 -231.465695)
		(end 89.74963 -231.394254)
		(width 0.088646)
		(layer "In4.Cu")
		(net "M_C_CPU1_SB_DQ<17>")
	)
	(arc
		(start 90.677492 -231.387396)
		(mid 90.492107 -231.339758)
		(end 90.307414 -231.389936)
		(width 0.088646)
		(layer "In4.Cu")
		(net "M_C_CPU1_SB_DQ<17>")
	)
	(arc
		(start 86.922864 -231.39019)
		(mid 86.735666 -231.340047)
		(end 86.548468 -231.39019)
		(width 0.088646)
		(layer "In4.Cu")
		(net "M_C_CPU1_SB_DQ<17>")
	)
	(arc
		(start 86.548468 -231.39019)
		(mid 86.265766 -231.465932)
		(end 85.983064 -231.39019)
		(width 0.088646)
		(layer "In4.Cu")
		(net "M_C_CPU1_SB_DQ<17>")
	)
	(arc
		(start 85.983064 -231.39019)
		(mid 85.795866 -231.340047)
		(end 85.608668 -231.39019)
		(width 0.088646)
		(layer "In4.Cu")
		(net "M_C_CPU1_SB_DQ<17>")
	)
	(arc
		(start 88.798654 -231.387904)
		(mid 88.612964 -231.339826)
		(end 88.427814 -231.389936)
		(width 0.088646)
		(layer "In4.Cu")
		(net "M_C_CPU1_SB_DQ<17>")
	)
	(arc
		(start 84.668868 -231.39019)
		(mid 84.307973 -231.462007)
		(end 83.977988 -231.299258)
		(width 0.088646)
		(layer "In4.Cu")
		(net "M_C_CPU1_SB_DQ<17>")
	)
	(arc
		(start 87.862664 -231.39019)
		(mid 87.675466 -231.340047)
		(end 87.488268 -231.39019)
		(width 0.088646)
		(layer "In4.Cu")
		(net "M_C_CPU1_SB_DQ<17>")
	)
	(arc
		(start 91.247214 -231.389936)
		(mid 90.968891 -231.465695)
		(end 90.68943 -231.394254)
		(width 0.088646)
		(layer "In4.Cu")
		(net "M_C_CPU1_SB_DQ<17>")
	)
	(arc
		(start 85.608668 -231.39019)
		(mid 85.325966 -231.465932)
		(end 85.043264 -231.39019)
		(width 0.088646)
		(layer "In4.Cu")
		(net "M_C_CPU1_SB_DQ<17>")
	)
	(arc
		(start 89.367614 -231.389936)
		(mid 89.089291 -231.465695)
		(end 88.80983 -231.394254)
		(width 0.088646)
		(layer "In4.Cu")
		(net "M_C_CPU1_SB_DQ<17>")
	)
	(arc
		(start 91.904566 -230.900478)
		(mid 91.627386 -231.143439)
		(end 91.32062 -231.347772)
		(width 0.088646)
		(layer "In4.Cu")
		(net "M_C_CPU1_SB_DQ<17>")
	)
	(segment
		(start 25.642062 -213.03361)
		(end 26.20391 -213.03361)
		(width 0.20066)
		(layer "F.Cu")
		(net "M_C_CPU1_SB_DQ<16>")
	)
	(segment
		(start 28.977844 -213.041738)
		(end 29.402786 -213.46668)
		(width 0.20066)
		(layer "F.Cu")
		(net "M_C_CPU1_SB_DQ<16>")
	)
	(segment
		(start 26.459942 -213.041738)
		(end 28.529026 -213.041738)
		(width 0.1016)
		(layer "F.Cu")
		(net "M_C_CPU1_SB_DQ<16>")
	)
	(segment
		(start 31.876746 -213.46668)
		(end 30.771846 -213.46668)
		(width 0.20066)
		(layer "F.Cu")
		(net "M_C_CPU1_SB_DQ<16>")
	)
	(segment
		(start 24.562308 -213.46668)
		(end 24.801068 -213.70544)
		(width 0.20066)
		(layer "F.Cu")
		(net "M_C_CPU1_SB_DQ<16>")
	)
	(segment
		(start 25.432512 -213.24316)
		(end 25.642062 -213.03361)
		(width 0.20066)
		(layer "F.Cu")
		(net "M_C_CPU1_SB_DQ<16>")
	)
	(segment
		(start 92.374212 -232.250234)
		(end 92.374212 -231.714548)
		(width 0.20066)
		(layer "F.Cu")
		(net "M_C_CPU1_SB_DQ<16>")
	)
	(segment
		(start 26.212038 -213.041738)
		(end 26.459942 -213.041738)
		(width 0.101854)
		(layer "F.Cu")
		(net "M_C_CPU1_SB_DQ<16>")
	)
	(segment
		(start 24.801068 -213.70544)
		(end 25.259792 -213.70544)
		(width 0.20066)
		(layer "F.Cu")
		(net "M_C_CPU1_SB_DQ<16>")
	)
	(segment
		(start 92.374466 -232.250488)
		(end 92.374212 -232.250234)
		(width 0.20066)
		(layer "F.Cu")
		(net "M_C_CPU1_SB_DQ<16>")
	)
	(segment
		(start 23.228046 -213.46668)
		(end 24.562308 -213.46668)
		(width 0.20066)
		(layer "F.Cu")
		(net "M_C_CPU1_SB_DQ<16>")
	)
	(segment
		(start 25.259792 -213.70544)
		(end 25.432512 -213.53272)
		(width 0.20066)
		(layer "F.Cu")
		(net "M_C_CPU1_SB_DQ<16>")
	)
	(segment
		(start 28.529026 -213.041738)
		(end 28.977844 -213.041738)
		(width 0.20066)
		(layer "F.Cu")
		(net "M_C_CPU1_SB_DQ<16>")
	)
	(segment
		(start 26.20391 -213.03361)
		(end 26.212038 -213.041738)
		(width 0.101854)
		(layer "F.Cu")
		(net "M_C_CPU1_SB_DQ<16>")
	)
	(segment
		(start 25.432512 -213.53272)
		(end 25.432512 -213.24316)
		(width 0.20066)
		(layer "F.Cu")
		(net "M_C_CPU1_SB_DQ<16>")
	)
	(segment
		(start 29.402786 -213.46668)
		(end 30.771846 -213.46668)
		(width 0.20066)
		(layer "F.Cu")
		(net "M_C_CPU1_SB_DQ<16>")
	)
	(segment
		(start 61.137546 -216.321386)
		(end 60.954666 -216.504266)
		(width 0.18288)
		(layer "In4.Cu")
		(net "M_C_CPU1_SB_DQ<16>")
	)
	(segment
		(start 91.717114 -232.204006)
		(end 91.711272 -232.207308)
		(width 0.088646)
		(layer "In4.Cu")
		(net "M_C_CPU1_SB_DQ<16>")
	)
	(segment
		(start 89.837514 -232.204006)
		(end 89.831672 -232.207308)
		(width 0.088646)
		(layer "In4.Cu")
		(net "M_C_CPU1_SB_DQ<16>")
	)
	(segment
		(start 32.301942 -213.891876)
		(end 31.876746 -213.46668)
		(width 0.18288)
		(layer "In4.Cu")
		(net "M_C_CPU1_SB_DQ<16>")
	)
	(segment
		(start 57.271412 -216.379806)
		(end 57.088532 -216.196926)
		(width 0.18288)
		(layer "In4.Cu")
		(net "M_C_CPU1_SB_DQ<16>")
	)
	(segment
		(start 60.638182 -216.504266)
		(end 60.446666 -216.31275)
		(width 0.18288)
		(layer "In4.Cu")
		(net "M_C_CPU1_SB_DQ<16>")
	)
	(segment
		(start 86.078568 -232.204006)
		(end 86.068154 -232.210102)
		(width 0.088646)
		(layer "In4.Cu")
		(net "M_C_CPU1_SB_DQ<16>")
	)
	(segment
		(start 60.263786 -215.416638)
		(end 59.309254 -215.416638)
		(width 0.18288)
		(layer "In4.Cu")
		(net "M_C_CPU1_SB_DQ<16>")
	)
	(segment
		(start 89.843356 -232.20045)
		(end 89.837514 -232.204006)
		(width 0.088646)
		(layer "In4.Cu")
		(net "M_C_CPU1_SB_DQ<16>")
	)
	(segment
		(start 61.320426 -215.416638)
		(end 61.137546 -215.599518)
		(width 0.18288)
		(layer "In4.Cu")
		(net "M_C_CPU1_SB_DQ<16>")
	)
	(segment
		(start 57.779412 -215.938862)
		(end 57.779412 -216.196926)
		(width 0.18288)
		(layer "In4.Cu")
		(net "M_C_CPU1_SB_DQ<16>")
	)
	(segment
		(start 82.708496 -231.48671)
		(end 76.66482 -231.48671)
		(width 0.18288)
		(layer "In4.Cu")
		(net "M_C_CPU1_SB_DQ<16>")
	)
	(segment
		(start 91.821 -232.142792)
		(end 91.717114 -232.204006)
		(width 0.088646)
		(layer "In4.Cu")
		(net "M_C_CPU1_SB_DQ<16>")
	)
	(segment
		(start 56.397652 -215.938862)
		(end 56.397652 -216.196926)
		(width 0.18288)
		(layer "In4.Cu")
		(net "M_C_CPU1_SB_DQ<16>")
	)
	(segment
		(start 88.897714 -232.204006)
		(end 88.893142 -232.206546)
		(width 0.088646)
		(layer "In4.Cu")
		(net "M_C_CPU1_SB_DQ<16>")
	)
	(segment
		(start 60.446666 -216.31275)
		(end 60.446666 -215.599518)
		(width 0.18288)
		(layer "In4.Cu")
		(net "M_C_CPU1_SB_DQ<16>")
	)
	(segment
		(start 55.706772 -216.196926)
		(end 55.706772 -215.938862)
		(width 0.18288)
		(layer "In4.Cu")
		(net "M_C_CPU1_SB_DQ<16>")
	)
	(segment
		(start 62.331092 -215.416638)
		(end 61.320426 -215.416638)
		(width 0.18288)
		(layer "In4.Cu")
		(net "M_C_CPU1_SB_DQ<16>")
	)
	(segment
		(start 56.214772 -216.379806)
		(end 55.889652 -216.379806)
		(width 0.18288)
		(layer "In4.Cu")
		(net "M_C_CPU1_SB_DQ<16>")
	)
	(segment
		(start 56.397652 -216.196926)
		(end 56.214772 -216.379806)
		(width 0.18288)
		(layer "In4.Cu")
		(net "M_C_CPU1_SB_DQ<16>")
	)
	(segment
		(start 76.66482 -231.48671)
		(end 68.870068 -223.691958)
		(width 0.18288)
		(layer "In4.Cu")
		(net "M_C_CPU1_SB_DQ<16>")
	)
	(segment
		(start 57.596532 -216.379806)
		(end 57.271412 -216.379806)
		(width 0.18288)
		(layer "In4.Cu")
		(net "M_C_CPU1_SB_DQ<16>")
	)
	(segment
		(start 56.905652 -215.755982)
		(end 56.580532 -215.755982)
		(width 0.18288)
		(layer "In4.Cu")
		(net "M_C_CPU1_SB_DQ<16>")
	)
	(segment
		(start 58.96991 -215.755982)
		(end 57.962292 -215.755982)
		(width 0.18288)
		(layer "In4.Cu")
		(net "M_C_CPU1_SB_DQ<16>")
	)
	(segment
		(start 88.903556 -232.20045)
		(end 88.897714 -232.204006)
		(width 0.088646)
		(layer "In4.Cu")
		(net "M_C_CPU1_SB_DQ<16>")
	)
	(segment
		(start 49.691798 -216.441782)
		(end 40.592502 -216.441782)
		(width 0.18288)
		(layer "In4.Cu")
		(net "M_C_CPU1_SB_DQ<16>")
	)
	(segment
		(start 54.85257 -215.591898)
		(end 50.541682 -215.591898)
		(width 0.18288)
		(layer "In4.Cu")
		(net "M_C_CPU1_SB_DQ<16>")
	)
	(segment
		(start 57.088532 -216.196926)
		(end 57.088532 -215.938862)
		(width 0.18288)
		(layer "In4.Cu")
		(net "M_C_CPU1_SB_DQ<16>")
	)
	(segment
		(start 57.779412 -216.196926)
		(end 57.596532 -216.379806)
		(width 0.18288)
		(layer "In4.Cu")
		(net "M_C_CPU1_SB_DQ<16>")
	)
	(segment
		(start 55.523892 -215.755982)
		(end 55.016654 -215.755982)
		(width 0.18288)
		(layer "In4.Cu")
		(net "M_C_CPU1_SB_DQ<16>")
	)
	(segment
		(start 92.374212 -231.714548)
		(end 92.373958 -231.714802)
		(width 0.088646)
		(layer "In4.Cu")
		(net "M_C_CPU1_SB_DQ<16>")
	)
	(segment
		(start 60.446666 -215.599518)
		(end 60.263786 -215.416638)
		(width 0.18288)
		(layer "In4.Cu")
		(net "M_C_CPU1_SB_DQ<16>")
	)
	(segment
		(start 38.042596 -213.891876)
		(end 32.301942 -213.891876)
		(width 0.18288)
		(layer "In4.Cu")
		(net "M_C_CPU1_SB_DQ<16>")
	)
	(segment
		(start 90.777314 -232.204006)
		(end 90.771472 -232.207308)
		(width 0.088646)
		(layer "In4.Cu")
		(net "M_C_CPU1_SB_DQ<16>")
	)
	(segment
		(start 83.033616 -231.48671)
		(end 82.708496 -231.48671)
		(width 0.088646)
		(layer "In4.Cu")
		(net "M_C_CPU1_SB_DQ<16>")
	)
	(segment
		(start 55.889652 -216.379806)
		(end 55.706772 -216.196926)
		(width 0.18288)
		(layer "In4.Cu")
		(net "M_C_CPU1_SB_DQ<16>")
	)
	(segment
		(start 56.580532 -215.755982)
		(end 56.397652 -215.938862)
		(width 0.18288)
		(layer "In4.Cu")
		(net "M_C_CPU1_SB_DQ<16>")
	)
	(segment
		(start 83.781646 -232.23474)
		(end 83.033616 -231.48671)
		(width 0.088646)
		(layer "In4.Cu")
		(net "M_C_CPU1_SB_DQ<16>")
	)
	(segment
		(start 40.592502 -216.441782)
		(end 38.042596 -213.891876)
		(width 0.18288)
		(layer "In4.Cu")
		(net "M_C_CPU1_SB_DQ<16>")
	)
	(segment
		(start 85.138514 -232.204006)
		(end 85.123782 -232.212642)
		(width 0.088646)
		(layer "In4.Cu")
		(net "M_C_CPU1_SB_DQ<16>")
	)
	(segment
		(start 57.088532 -215.938862)
		(end 56.905652 -215.755982)
		(width 0.18288)
		(layer "In4.Cu")
		(net "M_C_CPU1_SB_DQ<16>")
	)
	(segment
		(start 63.119762 -216.205308)
		(end 62.331092 -215.416638)
		(width 0.18288)
		(layer "In4.Cu")
		(net "M_C_CPU1_SB_DQ<16>")
	)
	(segment
		(start 57.962292 -215.755982)
		(end 57.779412 -215.938862)
		(width 0.18288)
		(layer "In4.Cu")
		(net "M_C_CPU1_SB_DQ<16>")
	)
	(segment
		(start 50.541682 -215.591898)
		(end 49.691798 -216.441782)
		(width 0.18288)
		(layer "In4.Cu")
		(net "M_C_CPU1_SB_DQ<16>")
	)
	(segment
		(start 59.309254 -215.416638)
		(end 58.96991 -215.755982)
		(width 0.18288)
		(layer "In4.Cu")
		(net "M_C_CPU1_SB_DQ<16>")
	)
	(segment
		(start 60.954666 -216.504266)
		(end 60.638182 -216.504266)
		(width 0.18288)
		(layer "In4.Cu")
		(net "M_C_CPU1_SB_DQ<16>")
	)
	(segment
		(start 61.137546 -215.599518)
		(end 61.137546 -216.321386)
		(width 0.18288)
		(layer "In4.Cu")
		(net "M_C_CPU1_SB_DQ<16>")
	)
	(segment
		(start 87.957914 -232.204006)
		(end 87.958168 -232.204006)
		(width 0.088646)
		(layer "In4.Cu")
		(net "M_C_CPU1_SB_DQ<16>")
	)
	(segment
		(start 55.016654 -215.755982)
		(end 54.85257 -215.591898)
		(width 0.18288)
		(layer "In4.Cu")
		(net "M_C_CPU1_SB_DQ<16>")
	)
	(segment
		(start 68.870068 -223.691958)
		(end 67.009772 -219.200984)
		(width 0.18288)
		(layer "In4.Cu")
		(net "M_C_CPU1_SB_DQ<16>")
	)
	(segment
		(start 67.009772 -219.200984)
		(end 64.014096 -216.205308)
		(width 0.18288)
		(layer "In4.Cu")
		(net "M_C_CPU1_SB_DQ<16>")
	)
	(segment
		(start 90.783156 -232.20045)
		(end 90.777314 -232.204006)
		(width 0.088646)
		(layer "In4.Cu")
		(net "M_C_CPU1_SB_DQ<16>")
	)
	(segment
		(start 64.014096 -216.205308)
		(end 63.119762 -216.205308)
		(width 0.18288)
		(layer "In4.Cu")
		(net "M_C_CPU1_SB_DQ<16>")
	)
	(segment
		(start 55.706772 -215.938862)
		(end 55.523892 -215.755982)
		(width 0.18288)
		(layer "In4.Cu")
		(net "M_C_CPU1_SB_DQ<16>")
	)
	(arc
		(start 92.373958 -231.714802)
		(mid 92.111028 -231.946302)
		(end 91.821 -232.142792)
		(width 0.088646)
		(layer "In4.Cu")
		(net "M_C_CPU1_SB_DQ<16>")
	)
	(arc
		(start 86.068154 -232.210102)
		(mid 85.789722 -232.279948)
		(end 85.51291 -232.204006)
		(width 0.088646)
		(layer "In4.Cu")
		(net "M_C_CPU1_SB_DQ<16>")
	)
	(arc
		(start 85.51291 -232.204006)
		(mid 85.325712 -232.153863)
		(end 85.138514 -232.204006)
		(width 0.088646)
		(layer "In4.Cu")
		(net "M_C_CPU1_SB_DQ<16>")
	)
	(arc
		(start 90.212164 -232.203752)
		(mid 90.02821 -232.153657)
		(end 89.843356 -232.20045)
		(width 0.088646)
		(layer "In4.Cu")
		(net "M_C_CPU1_SB_DQ<16>")
	)
	(arc
		(start 91.151964 -232.203752)
		(mid 90.96801 -232.153657)
		(end 90.783156 -232.20045)
		(width 0.088646)
		(layer "In4.Cu")
		(net "M_C_CPU1_SB_DQ<16>")
	)
	(arc
		(start 89.272364 -232.203752)
		(mid 89.08841 -232.153657)
		(end 88.903556 -232.20045)
		(width 0.088646)
		(layer "In4.Cu")
		(net "M_C_CPU1_SB_DQ<16>")
	)
	(arc
		(start 84.198714 -232.204006)
		(mid 84.080083 -232.255526)
		(end 83.952842 -232.278682)
		(width 0.088646)
		(layer "In4.Cu")
		(net "M_C_CPU1_SB_DQ<16>")
	)
	(arc
		(start 87.392764 -232.204006)
		(mid 87.205566 -232.153863)
		(end 87.018368 -232.204006)
		(width 0.088646)
		(layer "In4.Cu")
		(net "M_C_CPU1_SB_DQ<16>")
	)
	(arc
		(start 85.123782 -232.212642)
		(mid 84.847307 -232.279962)
		(end 84.57311 -232.204006)
		(width 0.088646)
		(layer "In4.Cu")
		(net "M_C_CPU1_SB_DQ<16>")
	)
	(arc
		(start 90.771472 -232.207308)
		(mid 90.491337 -232.279624)
		(end 90.212164 -232.203752)
		(width 0.088646)
		(layer "In4.Cu")
		(net "M_C_CPU1_SB_DQ<16>")
	)
	(arc
		(start 83.952842 -232.278682)
		(mid 83.906771 -232.279135)
		(end 83.860894 -232.274872)
		(width 0.088646)
		(layer "In4.Cu")
		(net "M_C_CPU1_SB_DQ<16>")
	)
	(arc
		(start 83.860894 -232.274872)
		(mid 83.818026 -232.261211)
		(end 83.781646 -232.23474)
		(width 0.088646)
		(layer "In4.Cu")
		(net "M_C_CPU1_SB_DQ<16>")
	)
	(arc
		(start 88.893142 -232.206546)
		(mid 88.612507 -232.279714)
		(end 88.332564 -232.204006)
		(width 0.088646)
		(layer "In4.Cu")
		(net "M_C_CPU1_SB_DQ<16>")
	)
	(arc
		(start 87.958168 -232.204006)
		(mid 87.675466 -232.279782)
		(end 87.392764 -232.204006)
		(width 0.088646)
		(layer "In4.Cu")
		(net "M_C_CPU1_SB_DQ<16>")
	)
	(arc
		(start 84.57311 -232.204006)
		(mid 84.385912 -232.153863)
		(end 84.198714 -232.204006)
		(width 0.088646)
		(layer "In4.Cu")
		(net "M_C_CPU1_SB_DQ<16>")
	)
	(arc
		(start 86.452964 -232.204006)
		(mid 86.265766 -232.153863)
		(end 86.078568 -232.204006)
		(width 0.088646)
		(layer "In4.Cu")
		(net "M_C_CPU1_SB_DQ<16>")
	)
	(arc
		(start 87.018368 -232.204006)
		(mid 86.735666 -232.279782)
		(end 86.452964 -232.204006)
		(width 0.088646)
		(layer "In4.Cu")
		(net "M_C_CPU1_SB_DQ<16>")
	)
	(arc
		(start 91.711272 -232.207308)
		(mid 91.431137 -232.279624)
		(end 91.151964 -232.203752)
		(width 0.088646)
		(layer "In4.Cu")
		(net "M_C_CPU1_SB_DQ<16>")
	)
	(arc
		(start 89.831672 -232.207308)
		(mid 89.551537 -232.279624)
		(end 89.272364 -232.203752)
		(width 0.088646)
		(layer "In4.Cu")
		(net "M_C_CPU1_SB_DQ<16>")
	)
	(arc
		(start 88.332564 -232.204006)
		(mid 88.145256 -232.153863)
		(end 87.957914 -232.204006)
		(width 0.088646)
		(layer "In4.Cu")
		(net "M_C_CPU1_SB_DQ<16>")
	)
	(segment
		(start 32.51708 -214.741506)
		(end 32.666178 -214.592408)
		(width 0.20066)
		(layer "F.Cu")
		(net "M_C_CPU1_SB_DQ<15>")
	)
	(segment
		(start 27.328114 -214.316564)
		(end 29.025342 -214.316564)
		(width 0.20066)
		(layer "F.Cu")
		(net "M_C_CPU1_SB_DQ<15>")
	)
	(segment
		(start 29.151326 -214.442548)
		(end 29.151326 -214.613236)
		(width 0.20066)
		(layer "F.Cu")
		(net "M_C_CPU1_SB_DQ<15>")
	)
	(segment
		(start 33.401762 -214.524082)
		(end 33.848294 -214.524082)
		(width 0.20066)
		(layer "F.Cu")
		(net "M_C_CPU1_SB_DQ<15>")
	)
	(segment
		(start 34.055812 -214.316564)
		(end 34.871914 -214.316564)
		(width 0.20066)
		(layer "F.Cu")
		(net "M_C_CPU1_SB_DQ<15>")
	)
	(segment
		(start 32.794702 -214.312246)
		(end 33.189926 -214.312246)
		(width 0.20066)
		(layer "F.Cu")
		(net "M_C_CPU1_SB_DQ<15>")
	)
	(segment
		(start 31.972758 -214.741506)
		(end 32.51708 -214.741506)
		(width 0.20066)
		(layer "F.Cu")
		(net "M_C_CPU1_SB_DQ<15>")
	)
	(segment
		(start 29.661866 -214.741506)
		(end 29.899864 -214.741506)
		(width 0.101854)
		(layer "F.Cu")
		(net "M_C_CPU1_SB_DQ<15>")
	)
	(segment
		(start 29.899864 -214.741506)
		(end 31.972758 -214.741506)
		(width 0.1016)
		(layer "F.Cu")
		(net "M_C_CPU1_SB_DQ<15>")
	)
	(segment
		(start 33.189926 -214.312246)
		(end 33.401762 -214.524082)
		(width 0.20066)
		(layer "F.Cu")
		(net "M_C_CPU1_SB_DQ<15>")
	)
	(segment
		(start 96.603312 -236.319822)
		(end 96.603566 -236.319568)
		(width 0.20066)
		(layer "F.Cu")
		(net "M_C_CPU1_SB_DQ<15>")
	)
	(segment
		(start 33.848294 -214.524082)
		(end 34.055812 -214.316564)
		(width 0.20066)
		(layer "F.Cu")
		(net "M_C_CPU1_SB_DQ<15>")
	)
	(segment
		(start 32.666178 -214.44077)
		(end 32.794702 -214.312246)
		(width 0.20066)
		(layer "F.Cu")
		(net "M_C_CPU1_SB_DQ<15>")
	)
	(segment
		(start 96.603566 -236.319568)
		(end 96.603566 -235.783882)
		(width 0.20066)
		(layer "F.Cu")
		(net "M_C_CPU1_SB_DQ<15>")
	)
	(segment
		(start 32.666178 -214.592408)
		(end 32.666178 -214.44077)
		(width 0.20066)
		(layer "F.Cu")
		(net "M_C_CPU1_SB_DQ<15>")
	)
	(segment
		(start 29.025342 -214.316564)
		(end 29.151326 -214.442548)
		(width 0.20066)
		(layer "F.Cu")
		(net "M_C_CPU1_SB_DQ<15>")
	)
	(segment
		(start 29.151326 -214.613236)
		(end 29.29382 -214.75573)
		(width 0.20066)
		(layer "F.Cu")
		(net "M_C_CPU1_SB_DQ<15>")
	)
	(segment
		(start 29.29382 -214.75573)
		(end 29.647642 -214.75573)
		(width 0.20066)
		(layer "F.Cu")
		(net "M_C_CPU1_SB_DQ<15>")
	)
	(segment
		(start 35.976814 -214.316564)
		(end 34.871914 -214.316564)
		(width 0.20066)
		(layer "F.Cu")
		(net "M_C_CPU1_SB_DQ<15>")
	)
	(segment
		(start 29.647642 -214.75573)
		(end 29.661866 -214.741506)
		(width 0.101854)
		(layer "F.Cu")
		(net "M_C_CPU1_SB_DQ<15>")
	)
	(segment
		(start 42.635932 -215.231472)
		(end 42.453052 -215.048592)
		(width 0.18288)
		(layer "In6.Cu")
		(net "M_C_CPU1_SB_DQ<15>")
	)
	(segment
		(start 83.958176 -234.115356)
		(end 83.958176 -233.566462)
		(width 0.088646)
		(layer "In6.Cu")
		(net "M_C_CPU1_SB_DQ<15>")
	)
	(segment
		(start 66.35496 -219.918534)
		(end 64.865758 -219.918534)
		(width 0.18288)
		(layer "In6.Cu")
		(net "M_C_CPU1_SB_DQ<15>")
	)
	(segment
		(start 53.807106 -216.661238)
		(end 53.624226 -216.478358)
		(width 0.18288)
		(layer "In6.Cu")
		(net "M_C_CPU1_SB_DQ<15>")
	)
	(segment
		(start 49.447704 -215.593168)
		(end 46.784006 -215.593168)
		(width 0.18288)
		(layer "In6.Cu")
		(net "M_C_CPU1_SB_DQ<15>")
	)
	(segment
		(start 41.945052 -215.707976)
		(end 41.762172 -215.890856)
		(width 0.18288)
		(layer "In6.Cu")
		(net "M_C_CPU1_SB_DQ<15>")
	)
	(segment
		(start 86.463124 -234.474512)
		(end 86.45271 -234.480608)
		(width 0.088646)
		(layer "In6.Cu")
		(net "M_C_CPU1_SB_DQ<15>")
	)
	(segment
		(start 87.488268 -235.294678)
		(end 87.479378 -235.289598)
		(width 0.088646)
		(layer "In6.Cu")
		(net "M_C_CPU1_SB_DQ<15>")
	)
	(segment
		(start 59.314842 -216.684098)
		(end 58.944764 -216.31402)
		(width 0.18288)
		(layer "In6.Cu")
		(net "M_C_CPU1_SB_DQ<15>")
	)
	(segment
		(start 94.066614 -235.294424)
		(end 94.051882 -235.285788)
		(width 0.088646)
		(layer "In6.Cu")
		(net "M_C_CPU1_SB_DQ<15>")
	)
	(segment
		(start 55.45963 -216.31402)
		(end 55.112412 -216.661238)
		(width 0.18288)
		(layer "In6.Cu")
		(net "M_C_CPU1_SB_DQ<15>")
	)
	(segment
		(start 53.116226 -216.001346)
		(end 52.933346 -216.184226)
		(width 0.18288)
		(layer "In6.Cu")
		(net "M_C_CPU1_SB_DQ<15>")
	)
	(segment
		(start 92.187014 -235.294424)
		(end 92.172282 -235.285788)
		(width 0.088646)
		(layer "In6.Cu")
		(net "M_C_CPU1_SB_DQ<15>")
	)
	(segment
		(start 52.933346 -216.184226)
		(end 52.933346 -216.478358)
		(width 0.18288)
		(layer "In6.Cu")
		(net "M_C_CPU1_SB_DQ<15>")
	)
	(segment
		(start 76.077318 -232.401364)
		(end 70.613016 -226.937062)
		(width 0.18288)
		(layer "In6.Cu")
		(net "M_C_CPU1_SB_DQ<15>")
	)
	(segment
		(start 57.504838 -215.701372)
		(end 57.321958 -215.518492)
		(width 0.18288)
		(layer "In6.Cu")
		(net "M_C_CPU1_SB_DQ<15>")
	)
	(segment
		(start 42.635932 -215.707976)
		(end 42.635932 -215.231472)
		(width 0.18288)
		(layer "In6.Cu")
		(net "M_C_CPU1_SB_DQ<15>")
	)
	(segment
		(start 53.624226 -216.478358)
		(end 53.624226 -216.184226)
		(width 0.18288)
		(layer "In6.Cu")
		(net "M_C_CPU1_SB_DQ<15>")
	)
	(segment
		(start 90.307668 -235.294424)
		(end 90.297254 -235.288328)
		(width 0.088646)
		(layer "In6.Cu")
		(net "M_C_CPU1_SB_DQ<15>")
	)
	(segment
		(start 57.504838 -216.13114)
		(end 57.504838 -215.701372)
		(width 0.18288)
		(layer "In6.Cu")
		(net "M_C_CPU1_SB_DQ<15>")
	)
	(segment
		(start 56.813958 -215.701372)
		(end 56.813958 -216.13114)
		(width 0.18288)
		(layer "In6.Cu")
		(net "M_C_CPU1_SB_DQ<15>")
	)
	(segment
		(start 56.813958 -216.13114)
		(end 56.631078 -216.31402)
		(width 0.18288)
		(layer "In6.Cu")
		(net "M_C_CPU1_SB_DQ<15>")
	)
	(segment
		(start 50.296318 -216.441782)
		(end 49.447704 -215.593168)
		(width 0.18288)
		(layer "In6.Cu")
		(net "M_C_CPU1_SB_DQ<15>")
	)
	(segment
		(start 93.126814 -235.294424)
		(end 93.112082 -235.285788)
		(width 0.088646)
		(layer "In6.Cu")
		(net "M_C_CPU1_SB_DQ<15>")
	)
	(segment
		(start 62.303406 -218.422982)
		(end 60.564522 -216.684098)
		(width 0.18288)
		(layer "In6.Cu")
		(net "M_C_CPU1_SB_DQ<15>")
	)
	(segment
		(start 60.564522 -216.684098)
		(end 59.314842 -216.684098)
		(width 0.18288)
		(layer "In6.Cu")
		(net "M_C_CPU1_SB_DQ<15>")
	)
	(segment
		(start 57.321958 -215.518492)
		(end 56.996838 -215.518492)
		(width 0.18288)
		(layer "In6.Cu")
		(net "M_C_CPU1_SB_DQ<15>")
	)
	(segment
		(start 83.958176 -233.566462)
		(end 82.793078 -232.401364)
		(width 0.088646)
		(layer "In6.Cu")
		(net "M_C_CPU1_SB_DQ<15>")
	)
	(segment
		(start 41.762172 -215.890856)
		(end 41.071292 -215.890856)
		(width 0.18288)
		(layer "In6.Cu")
		(net "M_C_CPU1_SB_DQ<15>")
	)
	(segment
		(start 84.573364 -234.480608)
		(end 84.564982 -234.485434)
		(width 0.088646)
		(layer "In6.Cu")
		(net "M_C_CPU1_SB_DQ<15>")
	)
	(segment
		(start 70.613016 -226.937062)
		(end 70.613016 -224.17659)
		(width 0.18288)
		(layer "In6.Cu")
		(net "M_C_CPU1_SB_DQ<15>")
	)
	(segment
		(start 36.654994 -214.994744)
		(end 35.976814 -214.316564)
		(width 0.18288)
		(layer "In6.Cu")
		(net "M_C_CPU1_SB_DQ<15>")
	)
	(segment
		(start 52.022756 -216.661238)
		(end 51.8033 -216.441782)
		(width 0.18288)
		(layer "In6.Cu")
		(net "M_C_CPU1_SB_DQ<15>")
	)
	(segment
		(start 89.367614 -235.294424)
		(end 89.352882 -235.285788)
		(width 0.088646)
		(layer "In6.Cu")
		(net "M_C_CPU1_SB_DQ<15>")
	)
	(segment
		(start 55.112412 -216.661238)
		(end 53.807106 -216.661238)
		(width 0.18288)
		(layer "In6.Cu")
		(net "M_C_CPU1_SB_DQ<15>")
	)
	(segment
		(start 70.613016 -224.17659)
		(end 66.35496 -219.918534)
		(width 0.18288)
		(layer "In6.Cu")
		(net "M_C_CPU1_SB_DQ<15>")
	)
	(segment
		(start 85.522308 -234.475528)
		(end 85.513418 -234.480862)
		(width 0.088646)
		(layer "In6.Cu")
		(net "M_C_CPU1_SB_DQ<15>")
	)
	(segment
		(start 86.08695 -234.485434)
		(end 86.078568 -234.480608)
		(width 0.088646)
		(layer "In6.Cu")
		(net "M_C_CPU1_SB_DQ<15>")
	)
	(segment
		(start 87.862664 -235.294424)
		(end 87.851742 -235.300774)
		(width 0.088646)
		(layer "In6.Cu")
		(net "M_C_CPU1_SB_DQ<15>")
	)
	(segment
		(start 44.173648 -216.543382)
		(end 43.521122 -215.890856)
		(width 0.18288)
		(layer "In6.Cu")
		(net "M_C_CPU1_SB_DQ<15>")
	)
	(segment
		(start 82.632296 -232.401364)
		(end 76.077318 -232.401364)
		(width 0.18288)
		(layer "In6.Cu")
		(net "M_C_CPU1_SB_DQ<15>")
	)
	(segment
		(start 90.692478 -235.288328)
		(end 90.682064 -235.294424)
		(width 0.088646)
		(layer "In6.Cu")
		(net "M_C_CPU1_SB_DQ<15>")
	)
	(segment
		(start 51.8033 -216.441782)
		(end 50.296318 -216.441782)
		(width 0.18288)
		(layer "In6.Cu")
		(net "M_C_CPU1_SB_DQ<15>")
	)
	(segment
		(start 40.17518 -214.994744)
		(end 36.654994 -214.994744)
		(width 0.18288)
		(layer "In6.Cu")
		(net "M_C_CPU1_SB_DQ<15>")
	)
	(segment
		(start 53.441346 -216.001346)
		(end 53.116226 -216.001346)
		(width 0.18288)
		(layer "In6.Cu")
		(net "M_C_CPU1_SB_DQ<15>")
	)
	(segment
		(start 41.071292 -215.890856)
		(end 40.17518 -214.994744)
		(width 0.18288)
		(layer "In6.Cu")
		(net "M_C_CPU1_SB_DQ<15>")
	)
	(segment
		(start 56.996838 -215.518492)
		(end 56.813958 -215.701372)
		(width 0.18288)
		(layer "In6.Cu")
		(net "M_C_CPU1_SB_DQ<15>")
	)
	(segment
		(start 95.006414 -235.294424)
		(end 94.991682 -235.285788)
		(width 0.088646)
		(layer "In6.Cu")
		(net "M_C_CPU1_SB_DQ<15>")
	)
	(segment
		(start 42.818812 -215.890856)
		(end 42.635932 -215.707976)
		(width 0.18288)
		(layer "In6.Cu")
		(net "M_C_CPU1_SB_DQ<15>")
	)
	(segment
		(start 63.370206 -218.422982)
		(end 62.303406 -218.422982)
		(width 0.18288)
		(layer "In6.Cu")
		(net "M_C_CPU1_SB_DQ<15>")
	)
	(segment
		(start 82.793078 -232.401364)
		(end 82.632296 -232.401364)
		(width 0.088646)
		(layer "In6.Cu")
		(net "M_C_CPU1_SB_DQ<15>")
	)
	(segment
		(start 41.945052 -215.231472)
		(end 41.945052 -215.707976)
		(width 0.18288)
		(layer "In6.Cu")
		(net "M_C_CPU1_SB_DQ<15>")
	)
	(segment
		(start 53.624226 -216.184226)
		(end 53.441346 -216.001346)
		(width 0.18288)
		(layer "In6.Cu")
		(net "M_C_CPU1_SB_DQ<15>")
	)
	(segment
		(start 58.944764 -216.31402)
		(end 57.687718 -216.31402)
		(width 0.18288)
		(layer "In6.Cu")
		(net "M_C_CPU1_SB_DQ<15>")
	)
	(segment
		(start 42.453052 -215.048592)
		(end 42.127932 -215.048592)
		(width 0.18288)
		(layer "In6.Cu")
		(net "M_C_CPU1_SB_DQ<15>")
	)
	(segment
		(start 56.631078 -216.31402)
		(end 55.45963 -216.31402)
		(width 0.18288)
		(layer "In6.Cu")
		(net "M_C_CPU1_SB_DQ<15>")
	)
	(segment
		(start 64.865758 -219.918534)
		(end 63.370206 -218.422982)
		(width 0.18288)
		(layer "In6.Cu")
		(net "M_C_CPU1_SB_DQ<15>")
	)
	(segment
		(start 84.578952 -234.477306)
		(end 84.573364 -234.480608)
		(width 0.088646)
		(layer "In6.Cu")
		(net "M_C_CPU1_SB_DQ<15>")
	)
	(segment
		(start 42.127932 -215.048592)
		(end 41.945052 -215.231472)
		(width 0.18288)
		(layer "In6.Cu")
		(net "M_C_CPU1_SB_DQ<15>")
	)
	(segment
		(start 45.833792 -216.543382)
		(end 44.173648 -216.543382)
		(width 0.18288)
		(layer "In6.Cu")
		(net "M_C_CPU1_SB_DQ<15>")
	)
	(segment
		(start 87.024464 -234.484164)
		(end 87.018368 -234.480608)
		(width 0.088646)
		(layer "In6.Cu")
		(net "M_C_CPU1_SB_DQ<15>")
	)
	(segment
		(start 43.521122 -215.890856)
		(end 42.818812 -215.890856)
		(width 0.18288)
		(layer "In6.Cu")
		(net "M_C_CPU1_SB_DQ<15>")
	)
	(segment
		(start 84.120736 -234.42168)
		(end 84.059776 -234.36072)
		(width 0.088646)
		(layer "In6.Cu")
		(net "M_C_CPU1_SB_DQ<15>")
	)
	(segment
		(start 84.059776 -234.36072)
		(end 83.958176 -234.115356)
		(width 0.088646)
		(layer "In6.Cu")
		(net "M_C_CPU1_SB_DQ<15>")
	)
	(segment
		(start 52.933346 -216.478358)
		(end 52.750466 -216.661238)
		(width 0.18288)
		(layer "In6.Cu")
		(net "M_C_CPU1_SB_DQ<15>")
	)
	(segment
		(start 52.750466 -216.661238)
		(end 52.022756 -216.661238)
		(width 0.18288)
		(layer "In6.Cu")
		(net "M_C_CPU1_SB_DQ<15>")
	)
	(segment
		(start 46.784006 -215.593168)
		(end 45.833792 -216.543382)
		(width 0.18288)
		(layer "In6.Cu")
		(net "M_C_CPU1_SB_DQ<15>")
	)
	(segment
		(start 88.427814 -235.294424)
		(end 88.4174 -235.288328)
		(width 0.088646)
		(layer "In6.Cu")
		(net "M_C_CPU1_SB_DQ<15>")
	)
	(segment
		(start 85.513418 -234.480862)
		(end 85.505036 -234.485688)
		(width 0.088646)
		(layer "In6.Cu")
		(net "M_C_CPU1_SB_DQ<15>")
	)
	(segment
		(start 57.687718 -216.31402)
		(end 57.504838 -216.13114)
		(width 0.18288)
		(layer "In6.Cu")
		(net "M_C_CPU1_SB_DQ<15>")
	)
	(arc
		(start 91.247214 -235.294424)
		(mid 90.970655 -235.218681)
		(end 90.692478 -235.288328)
		(width 0.088646)
		(layer "In6.Cu")
		(net "M_C_CPU1_SB_DQ<15>")
	)
	(arc
		(start 87.851742 -235.300774)
		(mid 87.669212 -235.344798)
		(end 87.488268 -235.294678)
		(width 0.088646)
		(layer "In6.Cu")
		(net "M_C_CPU1_SB_DQ<15>")
	)
	(arc
		(start 88.80221 -235.294424)
		(mid 88.615012 -235.344567)
		(end 88.427814 -235.294424)
		(width 0.088646)
		(layer "In6.Cu")
		(net "M_C_CPU1_SB_DQ<15>")
	)
	(arc
		(start 92.172282 -235.285788)
		(mid 91.895807 -235.218468)
		(end 91.62161 -235.294424)
		(width 0.088646)
		(layer "In6.Cu")
		(net "M_C_CPU1_SB_DQ<15>")
	)
	(arc
		(start 87.479378 -235.289598)
		(mid 87.348464 -235.153238)
		(end 87.300816 -234.97032)
		(width 0.088646)
		(layer "In6.Cu")
		(net "M_C_CPU1_SB_DQ<15>")
	)
	(arc
		(start 90.297254 -235.288328)
		(mid 90.018822 -235.218482)
		(end 89.74201 -235.294424)
		(width 0.088646)
		(layer "In6.Cu")
		(net "M_C_CPU1_SB_DQ<15>")
	)
	(arc
		(start 89.352882 -235.285788)
		(mid 89.076407 -235.218468)
		(end 88.80221 -235.294424)
		(width 0.088646)
		(layer "In6.Cu")
		(net "M_C_CPU1_SB_DQ<15>")
	)
	(arc
		(start 84.198714 -234.480608)
		(mid 84.157794 -234.453698)
		(end 84.120736 -234.42168)
		(width 0.088646)
		(layer "In6.Cu")
		(net "M_C_CPU1_SB_DQ<15>")
	)
	(arc
		(start 95.255334 -235.339382)
		(mid 95.126974 -235.338527)
		(end 95.006414 -235.294424)
		(width 0.088646)
		(layer "In6.Cu")
		(net "M_C_CPU1_SB_DQ<15>")
	)
	(arc
		(start 86.45271 -234.480608)
		(mid 86.270459 -234.530719)
		(end 86.08695 -234.485434)
		(width 0.088646)
		(layer "In6.Cu")
		(net "M_C_CPU1_SB_DQ<15>")
	)
	(arc
		(start 94.991682 -235.285788)
		(mid 94.715207 -235.218468)
		(end 94.44101 -235.294424)
		(width 0.088646)
		(layer "In6.Cu")
		(net "M_C_CPU1_SB_DQ<15>")
	)
	(arc
		(start 87.300816 -234.97032)
		(mid 87.226963 -234.690674)
		(end 87.024464 -234.484164)
		(width 0.088646)
		(layer "In6.Cu")
		(net "M_C_CPU1_SB_DQ<15>")
	)
	(arc
		(start 96.603566 -235.783882)
		(mid 95.984312 -235.395252)
		(end 95.255334 -235.339382)
		(width 0.088646)
		(layer "In6.Cu")
		(net "M_C_CPU1_SB_DQ<15>")
	)
	(arc
		(start 90.682064 -235.294424)
		(mid 90.494866 -235.344567)
		(end 90.307668 -235.294424)
		(width 0.088646)
		(layer "In6.Cu")
		(net "M_C_CPU1_SB_DQ<15>")
	)
	(arc
		(start 88.4174 -235.288328)
		(mid 88.139222 -235.218605)
		(end 87.862664 -235.294424)
		(width 0.088646)
		(layer "In6.Cu")
		(net "M_C_CPU1_SB_DQ<15>")
	)
	(arc
		(start 85.505036 -234.485688)
		(mid 85.321274 -234.531088)
		(end 85.138768 -234.480862)
		(width 0.088646)
		(layer "In6.Cu")
		(net "M_C_CPU1_SB_DQ<15>")
	)
	(arc
		(start 84.564982 -234.485434)
		(mid 84.38122 -234.530834)
		(end 84.198714 -234.480608)
		(width 0.088646)
		(layer "In6.Cu")
		(net "M_C_CPU1_SB_DQ<15>")
	)
	(arc
		(start 89.74201 -235.294424)
		(mid 89.554812 -235.344567)
		(end 89.367614 -235.294424)
		(width 0.088646)
		(layer "In6.Cu")
		(net "M_C_CPU1_SB_DQ<15>")
	)
	(arc
		(start 93.112082 -235.285788)
		(mid 92.835607 -235.218468)
		(end 92.56141 -235.294424)
		(width 0.088646)
		(layer "In6.Cu")
		(net "M_C_CPU1_SB_DQ<15>")
	)
	(arc
		(start 86.078568 -234.480608)
		(mid 85.801096 -234.40489)
		(end 85.522308 -234.475528)
		(width 0.088646)
		(layer "In6.Cu")
		(net "M_C_CPU1_SB_DQ<15>")
	)
	(arc
		(start 93.50121 -235.294424)
		(mid 93.314012 -235.344567)
		(end 93.126814 -235.294424)
		(width 0.088646)
		(layer "In6.Cu")
		(net "M_C_CPU1_SB_DQ<15>")
	)
	(arc
		(start 94.051882 -235.285788)
		(mid 93.775407 -235.218468)
		(end 93.50121 -235.294424)
		(width 0.088646)
		(layer "In6.Cu")
		(net "M_C_CPU1_SB_DQ<15>")
	)
	(arc
		(start 91.62161 -235.294424)
		(mid 91.434412 -235.344567)
		(end 91.247214 -235.294424)
		(width 0.088646)
		(layer "In6.Cu")
		(net "M_C_CPU1_SB_DQ<15>")
	)
	(arc
		(start 87.018368 -234.480608)
		(mid 86.741555 -234.404738)
		(end 86.463124 -234.474512)
		(width 0.088646)
		(layer "In6.Cu")
		(net "M_C_CPU1_SB_DQ<15>")
	)
	(arc
		(start 94.44101 -235.294424)
		(mid 94.253812 -235.344567)
		(end 94.066614 -235.294424)
		(width 0.088646)
		(layer "In6.Cu")
		(net "M_C_CPU1_SB_DQ<15>")
	)
	(arc
		(start 92.56141 -235.294424)
		(mid 92.374212 -235.344567)
		(end 92.187014 -235.294424)
		(width 0.088646)
		(layer "In6.Cu")
		(net "M_C_CPU1_SB_DQ<15>")
	)
	(arc
		(start 85.138768 -234.480862)
		(mid 84.85934 -234.40497)
		(end 84.578952 -234.477306)
		(width 0.088646)
		(layer "In6.Cu")
		(net "M_C_CPU1_SB_DQ<15>")
	)
	(segment
		(start 97.073466 -237.133892)
		(end 97.073212 -237.133638)
		(width 0.20066)
		(layer "F.Cu")
		(net "M_C_CPU1_SB_DQ<14>")
	)
	(segment
		(start 32.74949 -216.061036)
		(end 32.916876 -216.228422)
		(width 0.20066)
		(layer "F.Cu")
		(net "M_C_CPU1_SB_DQ<14>")
	)
	(segment
		(start 31.972758 -215.591644)
		(end 32.605726 -215.591644)
		(width 0.20066)
		(layer "F.Cu")
		(net "M_C_CPU1_SB_DQ<14>")
	)
	(segment
		(start 29.657802 -215.591644)
		(end 29.912818 -215.591644)
		(width 0.101854)
		(layer "F.Cu")
		(net "M_C_CPU1_SB_DQ<14>")
	)
	(segment
		(start 29.912818 -215.591644)
		(end 31.972758 -215.591644)
		(width 0.1016)
		(layer "F.Cu")
		(net "M_C_CPU1_SB_DQ<14>")
	)
	(segment
		(start 28.475178 -216.016586)
		(end 28.91028 -215.581484)
		(width 0.20066)
		(layer "F.Cu")
		(net "M_C_CPU1_SB_DQ<14>")
	)
	(segment
		(start 35.976814 -216.016586)
		(end 34.871914 -216.016586)
		(width 0.20066)
		(layer "F.Cu")
		(net "M_C_CPU1_SB_DQ<14>")
	)
	(segment
		(start 97.073212 -237.133638)
		(end 97.073212 -236.597952)
		(width 0.20066)
		(layer "F.Cu")
		(net "M_C_CPU1_SB_DQ<14>")
	)
	(segment
		(start 27.328114 -216.016586)
		(end 28.475178 -216.016586)
		(width 0.20066)
		(layer "F.Cu")
		(net "M_C_CPU1_SB_DQ<14>")
	)
	(segment
		(start 28.91028 -215.581484)
		(end 29.647642 -215.581484)
		(width 0.20066)
		(layer "F.Cu")
		(net "M_C_CPU1_SB_DQ<14>")
	)
	(segment
		(start 32.916876 -216.228422)
		(end 33.345374 -216.228422)
		(width 0.20066)
		(layer "F.Cu")
		(net "M_C_CPU1_SB_DQ<14>")
	)
	(segment
		(start 29.647642 -215.581484)
		(end 29.657802 -215.591644)
		(width 0.101854)
		(layer "F.Cu")
		(net "M_C_CPU1_SB_DQ<14>")
	)
	(segment
		(start 32.605726 -215.591644)
		(end 32.74949 -215.735408)
		(width 0.20066)
		(layer "F.Cu")
		(net "M_C_CPU1_SB_DQ<14>")
	)
	(segment
		(start 32.74949 -215.735408)
		(end 32.74949 -216.061036)
		(width 0.20066)
		(layer "F.Cu")
		(net "M_C_CPU1_SB_DQ<14>")
	)
	(segment
		(start 33.55721 -216.016586)
		(end 34.871914 -216.016586)
		(width 0.20066)
		(layer "F.Cu")
		(net "M_C_CPU1_SB_DQ<14>")
	)
	(segment
		(start 33.345374 -216.228422)
		(end 33.55721 -216.016586)
		(width 0.20066)
		(layer "F.Cu")
		(net "M_C_CPU1_SB_DQ<14>")
	)
	(segment
		(start 83.723988 -234.682538)
		(end 83.723988 -234.580684)
		(width 0.088646)
		(layer "In6.Cu")
		(net "M_C_CPU1_SB_DQ<14>")
	)
	(segment
		(start 52.660296 -218.398852)
		(end 52.477416 -218.215972)
		(width 0.18288)
		(layer "In6.Cu")
		(net "M_C_CPU1_SB_DQ<14>")
	)
	(segment
		(start 65.127378 -221.657926)
		(end 63.918592 -220.44914)
		(width 0.18288)
		(layer "In6.Cu")
		(net "M_C_CPU1_SB_DQ<14>")
	)
	(segment
		(start 91.162124 -236.102144)
		(end 91.15171 -236.10824)
		(width 0.088646)
		(layer "In6.Cu")
		(net "M_C_CPU1_SB_DQ<14>")
	)
	(segment
		(start 82.938366 -233.397044)
		(end 82.632296 -233.397044)
		(width 0.088646)
		(layer "In6.Cu")
		(net "M_C_CPU1_SB_DQ<14>")
	)
	(segment
		(start 83.44281 -233.901488)
		(end 82.938366 -233.397044)
		(width 0.088646)
		(layer "In6.Cu")
		(net "M_C_CPU1_SB_DQ<14>")
	)
	(segment
		(start 54.042056 -218.809062)
		(end 54.042056 -218.398852)
		(width 0.18288)
		(layer "In6.Cu")
		(net "M_C_CPU1_SB_DQ<14>")
	)
	(segment
		(start 38.49751 -216.567512)
		(end 38.49751 -216.284556)
		(width 0.18288)
		(layer "In6.Cu")
		(net "M_C_CPU1_SB_DQ<14>")
	)
	(segment
		(start 52.477416 -218.215972)
		(end 52.152296 -218.215972)
		(width 0.18288)
		(layer "In6.Cu")
		(net "M_C_CPU1_SB_DQ<14>")
	)
	(segment
		(start 84.260436 -235.218986)
		(end 83.723988 -234.682538)
		(width 0.088646)
		(layer "In6.Cu")
		(net "M_C_CPU1_SB_DQ<14>")
	)
	(segment
		(start 46.650656 -217.291666)
		(end 45.605446 -218.336876)
		(width 0.18288)
		(layer "In6.Cu")
		(net "M_C_CPU1_SB_DQ<14>")
	)
	(segment
		(start 86.83117 -235.792772)
		(end 86.83117 -235.769912)
		(width 0.088646)
		(layer "In6.Cu")
		(net "M_C_CPU1_SB_DQ<14>")
	)
	(segment
		(start 52.660296 -218.809062)
		(end 52.660296 -218.398852)
		(width 0.18288)
		(layer "In6.Cu")
		(net "M_C_CPU1_SB_DQ<14>")
	)
	(segment
		(start 52.152296 -218.215972)
		(end 51.969416 -218.398852)
		(width 0.18288)
		(layer "In6.Cu")
		(net "M_C_CPU1_SB_DQ<14>")
	)
	(segment
		(start 37.80663 -216.567512)
		(end 37.62375 -216.750392)
		(width 0.18288)
		(layer "In6.Cu")
		(net "M_C_CPU1_SB_DQ<14>")
	)
	(segment
		(start 38.49751 -216.284556)
		(end 38.31463 -216.101676)
		(width 0.18288)
		(layer "In6.Cu")
		(net "M_C_CPU1_SB_DQ<14>")
	)
	(segment
		(start 51.969416 -218.398852)
		(end 51.969416 -218.809062)
		(width 0.18288)
		(layer "In6.Cu")
		(net "M_C_CPU1_SB_DQ<14>")
	)
	(segment
		(start 61.525404 -219.51442)
		(end 60.34659 -218.335606)
		(width 0.18288)
		(layer "In6.Cu")
		(net "M_C_CPU1_SB_DQ<14>")
	)
	(segment
		(start 62.34938 -219.51442)
		(end 61.525404 -219.51442)
		(width 0.18288)
		(layer "In6.Cu")
		(net "M_C_CPU1_SB_DQ<14>")
	)
	(segment
		(start 83.723988 -234.580684)
		(end 83.44281 -233.901488)
		(width 0.088646)
		(layer "In6.Cu")
		(net "M_C_CPU1_SB_DQ<14>")
	)
	(segment
		(start 93.046296 -236.099604)
		(end 93.031564 -236.10824)
		(width 0.088646)
		(layer "In6.Cu")
		(net "M_C_CPU1_SB_DQ<14>")
	)
	(segment
		(start 38.68039 -216.750392)
		(end 38.49751 -216.567512)
		(width 0.18288)
		(layer "In6.Cu")
		(net "M_C_CPU1_SB_DQ<14>")
	)
	(segment
		(start 41.014904 -217.393266)
		(end 40.37203 -216.750392)
		(width 0.18288)
		(layer "In6.Cu")
		(net "M_C_CPU1_SB_DQ<14>")
	)
	(segment
		(start 55.82158 -218.335606)
		(end 55.165244 -218.991942)
		(width 0.18288)
		(layer "In6.Cu")
		(net "M_C_CPU1_SB_DQ<14>")
	)
	(segment
		(start 51.969416 -218.809062)
		(end 51.786536 -218.991942)
		(width 0.18288)
		(layer "In6.Cu")
		(net "M_C_CPU1_SB_DQ<14>")
	)
	(segment
		(start 37.98951 -216.101676)
		(end 37.80663 -216.284556)
		(width 0.18288)
		(layer "In6.Cu")
		(net "M_C_CPU1_SB_DQ<14>")
	)
	(segment
		(start 60.34659 -218.335606)
		(end 55.82158 -218.335606)
		(width 0.18288)
		(layer "In6.Cu")
		(net "M_C_CPU1_SB_DQ<14>")
	)
	(segment
		(start 84.385912 -235.218986)
		(end 84.260436 -235.218986)
		(width 0.088646)
		(layer "In6.Cu")
		(net "M_C_CPU1_SB_DQ<14>")
	)
	(segment
		(start 69.617336 -224.846134)
		(end 66.429128 -221.657926)
		(width 0.18288)
		(layer "In6.Cu")
		(net "M_C_CPU1_SB_DQ<14>")
	)
	(segment
		(start 53.168296 -218.991942)
		(end 52.843176 -218.991942)
		(width 0.18288)
		(layer "In6.Cu")
		(net "M_C_CPU1_SB_DQ<14>")
	)
	(segment
		(start 66.429128 -221.657926)
		(end 65.127378 -221.657926)
		(width 0.18288)
		(layer "In6.Cu")
		(net "M_C_CPU1_SB_DQ<14>")
	)
	(segment
		(start 50.406046 -218.991942)
		(end 48.70577 -217.291666)
		(width 0.18288)
		(layer "In6.Cu")
		(net "M_C_CPU1_SB_DQ<14>")
	)
	(segment
		(start 38.31463 -216.101676)
		(end 37.98951 -216.101676)
		(width 0.18288)
		(layer "In6.Cu")
		(net "M_C_CPU1_SB_DQ<14>")
	)
	(segment
		(start 37.80663 -216.284556)
		(end 37.80663 -216.567512)
		(width 0.18288)
		(layer "In6.Cu")
		(net "M_C_CPU1_SB_DQ<14>")
	)
	(segment
		(start 53.534056 -218.215972)
		(end 53.351176 -218.398852)
		(width 0.18288)
		(layer "In6.Cu")
		(net "M_C_CPU1_SB_DQ<14>")
	)
	(segment
		(start 87.40648 -236.100366)
		(end 87.392764 -236.108494)
		(width 0.088646)
		(layer "In6.Cu")
		(net "M_C_CPU1_SB_DQ<14>")
	)
	(segment
		(start 75.59294 -233.397044)
		(end 69.617336 -227.42144)
		(width 0.18288)
		(layer "In6.Cu")
		(net "M_C_CPU1_SB_DQ<14>")
	)
	(segment
		(start 43.079162 -218.336876)
		(end 42.135552 -217.393266)
		(width 0.18288)
		(layer "In6.Cu")
		(net "M_C_CPU1_SB_DQ<14>")
	)
	(segment
		(start 36.71062 -216.750392)
		(end 35.976814 -216.016586)
		(width 0.18288)
		(layer "In6.Cu")
		(net "M_C_CPU1_SB_DQ<14>")
	)
	(segment
		(start 53.351176 -218.809062)
		(end 53.168296 -218.991942)
		(width 0.18288)
		(layer "In6.Cu")
		(net "M_C_CPU1_SB_DQ<14>")
	)
	(segment
		(start 55.165244 -218.991942)
		(end 54.224936 -218.991942)
		(width 0.18288)
		(layer "In6.Cu")
		(net "M_C_CPU1_SB_DQ<14>")
	)
	(segment
		(start 90.222578 -236.102144)
		(end 90.212164 -236.10824)
		(width 0.088646)
		(layer "In6.Cu")
		(net "M_C_CPU1_SB_DQ<14>")
	)
	(segment
		(start 54.224936 -218.991942)
		(end 54.042056 -218.809062)
		(width 0.18288)
		(layer "In6.Cu")
		(net "M_C_CPU1_SB_DQ<14>")
	)
	(segment
		(start 53.351176 -218.398852)
		(end 53.351176 -218.809062)
		(width 0.18288)
		(layer "In6.Cu")
		(net "M_C_CPU1_SB_DQ<14>")
	)
	(segment
		(start 84.676996 -235.299504)
		(end 84.668614 -235.294678)
		(width 0.088646)
		(layer "In6.Cu")
		(net "M_C_CPU1_SB_DQ<14>")
	)
	(segment
		(start 52.843176 -218.991942)
		(end 52.660296 -218.809062)
		(width 0.18288)
		(layer "In6.Cu")
		(net "M_C_CPU1_SB_DQ<14>")
	)
	(segment
		(start 92.106496 -236.099604)
		(end 92.091764 -236.10824)
		(width 0.088646)
		(layer "In6.Cu")
		(net "M_C_CPU1_SB_DQ<14>")
	)
	(segment
		(start 48.70577 -217.291666)
		(end 46.650656 -217.291666)
		(width 0.18288)
		(layer "In6.Cu")
		(net "M_C_CPU1_SB_DQ<14>")
	)
	(segment
		(start 42.135552 -217.393266)
		(end 41.014904 -217.393266)
		(width 0.18288)
		(layer "In6.Cu")
		(net "M_C_CPU1_SB_DQ<14>")
	)
	(segment
		(start 40.37203 -216.750392)
		(end 38.68039 -216.750392)
		(width 0.18288)
		(layer "In6.Cu")
		(net "M_C_CPU1_SB_DQ<14>")
	)
	(segment
		(start 51.786536 -218.991942)
		(end 50.406046 -218.991942)
		(width 0.18288)
		(layer "In6.Cu")
		(net "M_C_CPU1_SB_DQ<14>")
	)
	(segment
		(start 63.918592 -220.44914)
		(end 63.2841 -220.44914)
		(width 0.18288)
		(layer "In6.Cu")
		(net "M_C_CPU1_SB_DQ<14>")
	)
	(segment
		(start 37.62375 -216.750392)
		(end 36.71062 -216.750392)
		(width 0.18288)
		(layer "In6.Cu")
		(net "M_C_CPU1_SB_DQ<14>")
	)
	(segment
		(start 85.992208 -235.289344)
		(end 85.983318 -235.294678)
		(width 0.088646)
		(layer "In6.Cu")
		(net "M_C_CPU1_SB_DQ<14>")
	)
	(segment
		(start 63.2841 -220.44914)
		(end 62.34938 -219.51442)
		(width 0.18288)
		(layer "In6.Cu")
		(net "M_C_CPU1_SB_DQ<14>")
	)
	(segment
		(start 82.632296 -233.397044)
		(end 75.59294 -233.397044)
		(width 0.18288)
		(layer "In6.Cu")
		(net "M_C_CPU1_SB_DQ<14>")
	)
	(segment
		(start 89.287096 -236.099604)
		(end 89.272364 -236.10824)
		(width 0.088646)
		(layer "In6.Cu")
		(net "M_C_CPU1_SB_DQ<14>")
	)
	(segment
		(start 54.042056 -218.398852)
		(end 53.859176 -218.215972)
		(width 0.18288)
		(layer "In6.Cu")
		(net "M_C_CPU1_SB_DQ<14>")
	)
	(segment
		(start 53.859176 -218.215972)
		(end 53.534056 -218.215972)
		(width 0.18288)
		(layer "In6.Cu")
		(net "M_C_CPU1_SB_DQ<14>")
	)
	(segment
		(start 69.617336 -227.42144)
		(end 69.617336 -224.846134)
		(width 0.18288)
		(layer "In6.Cu")
		(net "M_C_CPU1_SB_DQ<14>")
	)
	(segment
		(start 85.608922 -235.294678)
		(end 85.598508 -235.288582)
		(width 0.088646)
		(layer "In6.Cu")
		(net "M_C_CPU1_SB_DQ<14>")
	)
	(segment
		(start 45.605446 -218.336876)
		(end 43.079162 -218.336876)
		(width 0.18288)
		(layer "In6.Cu")
		(net "M_C_CPU1_SB_DQ<14>")
	)
	(arc
		(start 86.548468 -235.294424)
		(mid 86.270996 -235.218706)
		(end 85.992208 -235.289344)
		(width 0.088646)
		(layer "In6.Cu")
		(net "M_C_CPU1_SB_DQ<14>")
	)
	(arc
		(start 89.837768 -236.10824)
		(mid 89.563539 -236.032315)
		(end 89.287096 -236.099604)
		(width 0.088646)
		(layer "In6.Cu")
		(net "M_C_CPU1_SB_DQ<14>")
	)
	(arc
		(start 92.091764 -236.10824)
		(mid 91.904566 -236.158383)
		(end 91.717368 -236.10824)
		(width 0.088646)
		(layer "In6.Cu")
		(net "M_C_CPU1_SB_DQ<14>")
	)
	(arc
		(start 86.83117 -235.769912)
		(mid 86.751951 -235.495227)
		(end 86.548468 -235.294424)
		(width 0.088646)
		(layer "In6.Cu")
		(net "M_C_CPU1_SB_DQ<14>")
	)
	(arc
		(start 88.897968 -236.10824)
		(mid 88.615266 -236.032498)
		(end 88.332564 -236.10824)
		(width 0.088646)
		(layer "In6.Cu")
		(net "M_C_CPU1_SB_DQ<14>")
	)
	(arc
		(start 91.717368 -236.10824)
		(mid 91.440555 -236.032404)
		(end 91.162124 -236.102144)
		(width 0.088646)
		(layer "In6.Cu")
		(net "M_C_CPU1_SB_DQ<14>")
	)
	(arc
		(start 93.031564 -236.10824)
		(mid 92.844366 -236.158383)
		(end 92.657168 -236.10824)
		(width 0.088646)
		(layer "In6.Cu")
		(net "M_C_CPU1_SB_DQ<14>")
	)
	(arc
		(start 90.212164 -236.10824)
		(mid 90.024966 -236.158383)
		(end 89.837768 -236.10824)
		(width 0.088646)
		(layer "In6.Cu")
		(net "M_C_CPU1_SB_DQ<14>")
	)
	(arc
		(start 87.392764 -236.108494)
		(mid 87.205566 -236.158637)
		(end 87.018368 -236.108494)
		(width 0.088646)
		(layer "In6.Cu")
		(net "M_C_CPU1_SB_DQ<14>")
	)
	(arc
		(start 97.073212 -236.597952)
		(mid 96.631773 -236.302992)
		(end 96.11106 -236.199426)
		(width 0.088646)
		(layer "In6.Cu")
		(net "M_C_CPU1_SB_DQ<14>")
	)
	(arc
		(start 90.777314 -236.10824)
		(mid 90.500755 -236.032531)
		(end 90.222578 -236.102144)
		(width 0.088646)
		(layer "In6.Cu")
		(net "M_C_CPU1_SB_DQ<14>")
	)
	(arc
		(start 94.536768 -236.10824)
		(mid 94.254066 -236.032498)
		(end 93.971364 -236.10824)
		(width 0.088646)
		(layer "In6.Cu")
		(net "M_C_CPU1_SB_DQ<14>")
	)
	(arc
		(start 91.15171 -236.10824)
		(mid 90.964512 -236.158383)
		(end 90.777314 -236.10824)
		(width 0.088646)
		(layer "In6.Cu")
		(net "M_C_CPU1_SB_DQ<14>")
	)
	(arc
		(start 85.043264 -235.294678)
		(mid 84.860759 -235.344916)
		(end 84.676996 -235.299504)
		(width 0.088646)
		(layer "In6.Cu")
		(net "M_C_CPU1_SB_DQ<14>")
	)
	(arc
		(start 93.596968 -236.10824)
		(mid 93.322739 -236.032315)
		(end 93.046296 -236.099604)
		(width 0.088646)
		(layer "In6.Cu")
		(net "M_C_CPU1_SB_DQ<14>")
	)
	(arc
		(start 89.272364 -236.10824)
		(mid 89.085166 -236.158383)
		(end 88.897968 -236.10824)
		(width 0.088646)
		(layer "In6.Cu")
		(net "M_C_CPU1_SB_DQ<14>")
	)
	(arc
		(start 85.983318 -235.294678)
		(mid 85.79612 -235.344821)
		(end 85.608922 -235.294678)
		(width 0.088646)
		(layer "In6.Cu")
		(net "M_C_CPU1_SB_DQ<14>")
	)
	(arc
		(start 95.127826 -236.174026)
		(mid 94.825403 -236.203021)
		(end 94.536768 -236.10824)
		(width 0.088646)
		(layer "In6.Cu")
		(net "M_C_CPU1_SB_DQ<14>")
	)
	(arc
		(start 93.971364 -236.10824)
		(mid 93.784166 -236.158383)
		(end 93.596968 -236.10824)
		(width 0.088646)
		(layer "In6.Cu")
		(net "M_C_CPU1_SB_DQ<14>")
	)
	(arc
		(start 87.958168 -236.10824)
		(mid 87.683341 -236.032429)
		(end 87.40648 -236.100366)
		(width 0.088646)
		(layer "In6.Cu")
		(net "M_C_CPU1_SB_DQ<14>")
	)
	(arc
		(start 96.11106 -236.199426)
		(mid 95.619279 -236.193075)
		(end 95.127826 -236.174026)
		(width 0.088646)
		(layer "In6.Cu")
		(net "M_C_CPU1_SB_DQ<14>")
	)
	(arc
		(start 87.018368 -236.108494)
		(mid 86.883435 -235.97514)
		(end 86.83117 -235.792772)
		(width 0.088646)
		(layer "In6.Cu")
		(net "M_C_CPU1_SB_DQ<14>")
	)
	(arc
		(start 85.598508 -235.288582)
		(mid 85.320076 -235.218736)
		(end 85.043264 -235.294678)
		(width 0.088646)
		(layer "In6.Cu")
		(net "M_C_CPU1_SB_DQ<14>")
	)
	(arc
		(start 92.657168 -236.10824)
		(mid 92.382939 -236.032315)
		(end 92.106496 -236.099604)
		(width 0.088646)
		(layer "In6.Cu")
		(net "M_C_CPU1_SB_DQ<14>")
	)
	(arc
		(start 88.332564 -236.10824)
		(mid 88.145366 -236.158383)
		(end 87.958168 -236.10824)
		(width 0.088646)
		(layer "In6.Cu")
		(net "M_C_CPU1_SB_DQ<14>")
	)
	(arc
		(start 84.668614 -235.294678)
		(mid 84.532245 -235.238236)
		(end 84.385912 -235.218986)
		(width 0.088646)
		(layer "In6.Cu")
		(net "M_C_CPU1_SB_DQ<14>")
	)
	(segment
		(start 95.663512 -236.319822)
		(end 95.663766 -236.319568)
		(width 0.20066)
		(layer "F.Cu")
		(net "M_C_CPU1_SB_DQ<13>")
	)
	(segment
		(start 28.198318 -214.74176)
		(end 28.529026 -214.74176)
		(width 0.101854)
		(layer "F.Cu")
		(net "M_C_CPU1_SB_DQ<13>")
	)
	(segment
		(start 25.595072 -214.73287)
		(end 26.20391 -214.73287)
		(width 0.20066)
		(layer "F.Cu")
		(net "M_C_CPU1_SB_DQ<13>")
	)
	(segment
		(start 24.562308 -215.166702)
		(end 24.773636 -215.37803)
		(width 0.20066)
		(layer "F.Cu")
		(net "M_C_CPU1_SB_DQ<13>")
	)
	(segment
		(start 29.13253 -215.166702)
		(end 30.771846 -215.166702)
		(width 0.20066)
		(layer "F.Cu")
		(net "M_C_CPU1_SB_DQ<13>")
	)
	(segment
		(start 28.529026 -214.74176)
		(end 28.707588 -214.74176)
		(width 0.20066)
		(layer "F.Cu")
		(net "M_C_CPU1_SB_DQ<13>")
	)
	(segment
		(start 26.2128 -214.74176)
		(end 28.198318 -214.74176)
		(width 0.1016)
		(layer "F.Cu")
		(net "M_C_CPU1_SB_DQ<13>")
	)
	(segment
		(start 25.432512 -214.89543)
		(end 25.595072 -214.73287)
		(width 0.20066)
		(layer "F.Cu")
		(net "M_C_CPU1_SB_DQ<13>")
	)
	(segment
		(start 28.707588 -214.74176)
		(end 29.13253 -215.166702)
		(width 0.20066)
		(layer "F.Cu")
		(net "M_C_CPU1_SB_DQ<13>")
	)
	(segment
		(start 25.432512 -215.223598)
		(end 25.432512 -214.89543)
		(width 0.20066)
		(layer "F.Cu")
		(net "M_C_CPU1_SB_DQ<13>")
	)
	(segment
		(start 95.663766 -236.319568)
		(end 95.663766 -235.783882)
		(width 0.20066)
		(layer "F.Cu")
		(net "M_C_CPU1_SB_DQ<13>")
	)
	(segment
		(start 24.773636 -215.37803)
		(end 25.27808 -215.37803)
		(width 0.20066)
		(layer "F.Cu")
		(net "M_C_CPU1_SB_DQ<13>")
	)
	(segment
		(start 26.20391 -214.73287)
		(end 26.2128 -214.74176)
		(width 0.1016)
		(layer "F.Cu")
		(net "M_C_CPU1_SB_DQ<13>")
	)
	(segment
		(start 23.228046 -215.166702)
		(end 24.562308 -215.166702)
		(width 0.20066)
		(layer "F.Cu")
		(net "M_C_CPU1_SB_DQ<13>")
	)
	(segment
		(start 25.27808 -215.37803)
		(end 25.432512 -215.223598)
		(width 0.20066)
		(layer "F.Cu")
		(net "M_C_CPU1_SB_DQ<13>")
	)
	(segment
		(start 31.876746 -215.166702)
		(end 30.771846 -215.166702)
		(width 0.20066)
		(layer "F.Cu")
		(net "M_C_CPU1_SB_DQ<13>")
	)
	(segment
		(start 70.115176 -227.14331)
		(end 70.115176 -224.436686)
		(width 0.18288)
		(layer "In6.Cu")
		(net "M_C_CPU1_SB_DQ<13>")
	)
	(segment
		(start 75.87107 -232.899204)
		(end 70.115176 -227.14331)
		(width 0.18288)
		(layer "In6.Cu")
		(net "M_C_CPU1_SB_DQ<13>")
	)
	(segment
		(start 94.925896 -235.46816)
		(end 94.911164 -235.459524)
		(width 0.088646)
		(layer "In6.Cu")
		(net "M_C_CPU1_SB_DQ<13>")
	)
	(segment
		(start 83.76793 -234.16133)
		(end 83.76793 -233.714798)
		(width 0.088646)
		(layer "In6.Cu")
		(net "M_C_CPU1_SB_DQ<13>")
	)
	(segment
		(start 66.15557 -220.47708)
		(end 64.68999 -220.47708)
		(width 0.18288)
		(layer "In6.Cu")
		(net "M_C_CPU1_SB_DQ<13>")
	)
	(segment
		(start 88.347296 -235.46816)
		(end 88.332564 -235.459524)
		(width 0.088646)
		(layer "In6.Cu")
		(net "M_C_CPU1_SB_DQ<13>")
	)
	(segment
		(start 55.716424 -217.770456)
		(end 55.236872 -217.290904)
		(width 0.18288)
		(layer "In6.Cu")
		(net "M_C_CPU1_SB_DQ<13>")
	)
	(segment
		(start 46.789594 -216.441782)
		(end 45.943012 -217.288364)
		(width 0.18288)
		(layer "In6.Cu")
		(net "M_C_CPU1_SB_DQ<13>")
	)
	(segment
		(start 64.15532 -219.94241)
		(end 63.540386 -219.94241)
		(width 0.18288)
		(layer "In6.Cu")
		(net "M_C_CPU1_SB_DQ<13>")
	)
	(segment
		(start 82.952336 -232.899204)
		(end 82.632296 -232.899204)
		(width 0.088646)
		(layer "In6.Cu")
		(net "M_C_CPU1_SB_DQ<13>")
	)
	(segment
		(start 83.986116 -234.5563)
		(end 83.892898 -234.463082)
		(width 0.088646)
		(layer "In6.Cu")
		(net "M_C_CPU1_SB_DQ<13>")
	)
	(segment
		(start 91.162124 -235.46562)
		(end 91.15171 -235.459524)
		(width 0.088646)
		(layer "In6.Cu")
		(net "M_C_CPU1_SB_DQ<13>")
	)
	(segment
		(start 82.632296 -232.899204)
		(end 75.87107 -232.899204)
		(width 0.18288)
		(layer "In6.Cu")
		(net "M_C_CPU1_SB_DQ<13>")
	)
	(segment
		(start 39.953692 -215.59139)
		(end 32.301434 -215.59139)
		(width 0.18288)
		(layer "In6.Cu")
		(net "M_C_CPU1_SB_DQ<13>")
	)
	(segment
		(start 70.115176 -224.436686)
		(end 66.15557 -220.47708)
		(width 0.18288)
		(layer "In6.Cu")
		(net "M_C_CPU1_SB_DQ<13>")
	)
	(segment
		(start 55.236872 -217.290904)
		(end 50.092102 -217.290904)
		(width 0.18288)
		(layer "In6.Cu")
		(net "M_C_CPU1_SB_DQ<13>")
	)
	(segment
		(start 85.608922 -234.645962)
		(end 85.598508 -234.652058)
		(width 0.088646)
		(layer "In6.Cu")
		(net "M_C_CPU1_SB_DQ<13>")
	)
	(segment
		(start 40.75684 -216.394538)
		(end 39.953692 -215.59139)
		(width 0.18288)
		(layer "In6.Cu")
		(net "M_C_CPU1_SB_DQ<13>")
	)
	(segment
		(start 86.92261 -234.645962)
		(end 86.911688 -234.639612)
		(width 0.088646)
		(layer "In6.Cu")
		(net "M_C_CPU1_SB_DQ<13>")
	)
	(segment
		(start 89.287096 -235.46816)
		(end 89.272364 -235.459524)
		(width 0.088646)
		(layer "In6.Cu")
		(net "M_C_CPU1_SB_DQ<13>")
	)
	(segment
		(start 83.892898 -234.463082)
		(end 83.76793 -234.16133)
		(width 0.088646)
		(layer "In6.Cu")
		(net "M_C_CPU1_SB_DQ<13>")
	)
	(segment
		(start 93.986096 -235.46816)
		(end 93.971364 -235.459524)
		(width 0.088646)
		(layer "In6.Cu")
		(net "M_C_CPU1_SB_DQ<13>")
	)
	(segment
		(start 60.052966 -217.220038)
		(end 59.214766 -217.220038)
		(width 0.18288)
		(layer "In6.Cu")
		(net "M_C_CPU1_SB_DQ<13>")
	)
	(segment
		(start 59.214766 -217.220038)
		(end 58.664348 -217.770456)
		(width 0.18288)
		(layer "In6.Cu")
		(net "M_C_CPU1_SB_DQ<13>")
	)
	(segment
		(start 86.548214 -234.645708)
		(end 86.539324 -234.651042)
		(width 0.088646)
		(layer "In6.Cu")
		(net "M_C_CPU1_SB_DQ<13>")
	)
	(segment
		(start 84.676996 -234.641136)
		(end 84.65058 -234.656376)
		(width 0.088646)
		(layer "In6.Cu")
		(net "M_C_CPU1_SB_DQ<13>")
	)
	(segment
		(start 58.664348 -217.770456)
		(end 55.716424 -217.770456)
		(width 0.18288)
		(layer "In6.Cu")
		(net "M_C_CPU1_SB_DQ<13>")
	)
	(segment
		(start 93.046296 -235.46816)
		(end 93.031564 -235.459524)
		(width 0.088646)
		(layer "In6.Cu")
		(net "M_C_CPU1_SB_DQ<13>")
	)
	(segment
		(start 85.983064 -234.645962)
		(end 85.974682 -234.641136)
		(width 0.088646)
		(layer "In6.Cu")
		(net "M_C_CPU1_SB_DQ<13>")
	)
	(segment
		(start 64.68999 -220.47708)
		(end 64.15532 -219.94241)
		(width 0.18288)
		(layer "In6.Cu")
		(net "M_C_CPU1_SB_DQ<13>")
	)
	(segment
		(start 42.73931 -217.288364)
		(end 41.845484 -216.394538)
		(width 0.18288)
		(layer "In6.Cu")
		(net "M_C_CPU1_SB_DQ<13>")
	)
	(segment
		(start 92.106496 -235.46816)
		(end 92.091764 -235.459524)
		(width 0.088646)
		(layer "In6.Cu")
		(net "M_C_CPU1_SB_DQ<13>")
	)
	(segment
		(start 87.96909 -235.453428)
		(end 87.958168 -235.459778)
		(width 0.088646)
		(layer "In6.Cu")
		(net "M_C_CPU1_SB_DQ<13>")
	)
	(segment
		(start 41.845484 -216.394538)
		(end 40.75684 -216.394538)
		(width 0.18288)
		(layer "In6.Cu")
		(net "M_C_CPU1_SB_DQ<13>")
	)
	(segment
		(start 61.801502 -218.968574)
		(end 60.052966 -217.220038)
		(width 0.18288)
		(layer "In6.Cu")
		(net "M_C_CPU1_SB_DQ<13>")
	)
	(segment
		(start 63.540386 -219.94241)
		(end 62.56655 -218.968574)
		(width 0.18288)
		(layer "In6.Cu")
		(net "M_C_CPU1_SB_DQ<13>")
	)
	(segment
		(start 32.301434 -215.59139)
		(end 31.876746 -215.166702)
		(width 0.18288)
		(layer "In6.Cu")
		(net "M_C_CPU1_SB_DQ<13>")
	)
	(segment
		(start 87.392764 -235.459778)
		(end 87.380572 -235.452666)
		(width 0.088646)
		(layer "In6.Cu")
		(net "M_C_CPU1_SB_DQ<13>")
	)
	(segment
		(start 62.56655 -218.968574)
		(end 61.801502 -218.968574)
		(width 0.18288)
		(layer "In6.Cu")
		(net "M_C_CPU1_SB_DQ<13>")
	)
	(segment
		(start 86.936834 -234.65409)
		(end 86.92261 -234.645962)
		(width 0.088646)
		(layer "In6.Cu")
		(net "M_C_CPU1_SB_DQ<13>")
	)
	(segment
		(start 83.76793 -233.714798)
		(end 82.952336 -232.899204)
		(width 0.088646)
		(layer "In6.Cu")
		(net "M_C_CPU1_SB_DQ<13>")
	)
	(segment
		(start 90.777314 -235.459524)
		(end 90.7669 -235.46562)
		(width 0.088646)
		(layer "In6.Cu")
		(net "M_C_CPU1_SB_DQ<13>")
	)
	(segment
		(start 50.092102 -217.290904)
		(end 49.24298 -216.441782)
		(width 0.18288)
		(layer "In6.Cu")
		(net "M_C_CPU1_SB_DQ<13>")
	)
	(segment
		(start 49.24298 -216.441782)
		(end 46.789594 -216.441782)
		(width 0.18288)
		(layer "In6.Cu")
		(net "M_C_CPU1_SB_DQ<13>")
	)
	(segment
		(start 45.943012 -217.288364)
		(end 42.73931 -217.288364)
		(width 0.18288)
		(layer "In6.Cu")
		(net "M_C_CPU1_SB_DQ<13>")
	)
	(arc
		(start 87.380572 -235.452666)
		(mid 87.182282 -235.246707)
		(end 87.110062 -234.970066)
		(width 0.088646)
		(layer "In6.Cu")
		(net "M_C_CPU1_SB_DQ<13>")
	)
	(arc
		(start 92.091764 -235.459524)
		(mid 91.904566 -235.409381)
		(end 91.717368 -235.459524)
		(width 0.088646)
		(layer "In6.Cu")
		(net "M_C_CPU1_SB_DQ<13>")
	)
	(arc
		(start 93.031564 -235.459524)
		(mid 92.844366 -235.409381)
		(end 92.657168 -235.459524)
		(width 0.088646)
		(layer "In6.Cu")
		(net "M_C_CPU1_SB_DQ<13>")
	)
	(arc
		(start 85.043264 -234.645962)
		(mid 84.860759 -234.595724)
		(end 84.676996 -234.641136)
		(width 0.088646)
		(layer "In6.Cu")
		(net "M_C_CPU1_SB_DQ<13>")
	)
	(arc
		(start 94.911164 -235.459524)
		(mid 94.723966 -235.409381)
		(end 94.536768 -235.459524)
		(width 0.088646)
		(layer "In6.Cu")
		(net "M_C_CPU1_SB_DQ<13>")
	)
	(arc
		(start 91.717368 -235.459524)
		(mid 91.440555 -235.535394)
		(end 91.162124 -235.46562)
		(width 0.088646)
		(layer "In6.Cu")
		(net "M_C_CPU1_SB_DQ<13>")
	)
	(arc
		(start 93.596968 -235.459524)
		(mid 93.322769 -235.535359)
		(end 93.046296 -235.46816)
		(width 0.088646)
		(layer "In6.Cu")
		(net "M_C_CPU1_SB_DQ<13>")
	)
	(arc
		(start 89.837768 -235.459524)
		(mid 89.563569 -235.535359)
		(end 89.287096 -235.46816)
		(width 0.088646)
		(layer "In6.Cu")
		(net "M_C_CPU1_SB_DQ<13>")
	)
	(arc
		(start 86.911688 -234.639612)
		(mid 86.729158 -234.595588)
		(end 86.548214 -234.645708)
		(width 0.088646)
		(layer "In6.Cu")
		(net "M_C_CPU1_SB_DQ<13>")
	)
	(arc
		(start 91.15171 -235.459524)
		(mid 90.964512 -235.409381)
		(end 90.777314 -235.459524)
		(width 0.088646)
		(layer "In6.Cu")
		(net "M_C_CPU1_SB_DQ<13>")
	)
	(arc
		(start 94.536768 -235.459524)
		(mid 94.262569 -235.535359)
		(end 93.986096 -235.46816)
		(width 0.088646)
		(layer "In6.Cu")
		(net "M_C_CPU1_SB_DQ<13>")
	)
	(arc
		(start 87.958168 -235.459778)
		(mid 87.675466 -235.535554)
		(end 87.392764 -235.459778)
		(width 0.088646)
		(layer "In6.Cu")
		(net "M_C_CPU1_SB_DQ<13>")
	)
	(arc
		(start 86.539324 -234.651042)
		(mid 86.260536 -234.721605)
		(end 85.983064 -234.645962)
		(width 0.088646)
		(layer "In6.Cu")
		(net "M_C_CPU1_SB_DQ<13>")
	)
	(arc
		(start 95.131382 -235.532168)
		(mid 95.025555 -235.510055)
		(end 94.925896 -235.46816)
		(width 0.088646)
		(layer "In6.Cu")
		(net "M_C_CPU1_SB_DQ<13>")
	)
	(arc
		(start 89.272364 -235.459524)
		(mid 89.085166 -235.409381)
		(end 88.897968 -235.459524)
		(width 0.088646)
		(layer "In6.Cu")
		(net "M_C_CPU1_SB_DQ<13>")
	)
	(arc
		(start 95.663766 -235.783882)
		(mid 95.418624 -235.613501)
		(end 95.131382 -235.532168)
		(width 0.088646)
		(layer "In6.Cu")
		(net "M_C_CPU1_SB_DQ<13>")
	)
	(arc
		(start 88.332564 -235.459524)
		(mid 88.15162 -235.409433)
		(end 87.96909 -235.453428)
		(width 0.088646)
		(layer "In6.Cu")
		(net "M_C_CPU1_SB_DQ<13>")
	)
	(arc
		(start 92.657168 -235.459524)
		(mid 92.382969 -235.535359)
		(end 92.106496 -235.46816)
		(width 0.088646)
		(layer "In6.Cu")
		(net "M_C_CPU1_SB_DQ<13>")
	)
	(arc
		(start 90.7669 -235.46562)
		(mid 90.488722 -235.535343)
		(end 90.212164 -235.459524)
		(width 0.088646)
		(layer "In6.Cu")
		(net "M_C_CPU1_SB_DQ<13>")
	)
	(arc
		(start 84.65058 -234.656376)
		(mid 84.301889 -234.715659)
		(end 83.986116 -234.5563)
		(width 0.088646)
		(layer "In6.Cu")
		(net "M_C_CPU1_SB_DQ<13>")
	)
	(arc
		(start 93.971364 -235.459524)
		(mid 93.784166 -235.409381)
		(end 93.596968 -235.459524)
		(width 0.088646)
		(layer "In6.Cu")
		(net "M_C_CPU1_SB_DQ<13>")
	)
	(arc
		(start 90.212164 -235.459524)
		(mid 90.024966 -235.409381)
		(end 89.837768 -235.459524)
		(width 0.088646)
		(layer "In6.Cu")
		(net "M_C_CPU1_SB_DQ<13>")
	)
	(arc
		(start 85.598508 -234.652058)
		(mid 85.320076 -234.721904)
		(end 85.043264 -234.645962)
		(width 0.088646)
		(layer "In6.Cu")
		(net "M_C_CPU1_SB_DQ<13>")
	)
	(arc
		(start 88.897968 -235.459524)
		(mid 88.623769 -235.535359)
		(end 88.347296 -235.46816)
		(width 0.088646)
		(layer "In6.Cu")
		(net "M_C_CPU1_SB_DQ<13>")
	)
	(arc
		(start 85.974682 -234.641136)
		(mid 85.791174 -234.595858)
		(end 85.608922 -234.645962)
		(width 0.088646)
		(layer "In6.Cu")
		(net "M_C_CPU1_SB_DQ<13>")
	)
	(arc
		(start 87.110062 -234.970066)
		(mid 87.063923 -234.789881)
		(end 86.936834 -234.65409)
		(width 0.088646)
		(layer "In6.Cu")
		(net "M_C_CPU1_SB_DQ<13>")
	)
	(segment
		(start 23.228046 -216.866724)
		(end 24.562308 -216.866724)
		(width 0.20066)
		(layer "F.Cu")
		(net "M_C_CPU1_SB_DQ<12>")
	)
	(segment
		(start 24.562308 -216.866724)
		(end 24.801068 -217.105484)
		(width 0.20066)
		(layer "F.Cu")
		(net "M_C_CPU1_SB_DQ<12>")
	)
	(segment
		(start 26.212038 -216.441782)
		(end 26.459942 -216.441782)
		(width 0.101854)
		(layer "F.Cu")
		(net "M_C_CPU1_SB_DQ<12>")
	)
	(segment
		(start 26.20391 -216.433654)
		(end 26.212038 -216.441782)
		(width 0.101854)
		(layer "F.Cu")
		(net "M_C_CPU1_SB_DQ<12>")
	)
	(segment
		(start 25.642062 -216.433654)
		(end 26.20391 -216.433654)
		(width 0.20066)
		(layer "F.Cu")
		(net "M_C_CPU1_SB_DQ<12>")
	)
	(segment
		(start 28.529026 -216.441782)
		(end 28.977844 -216.441782)
		(width 0.20066)
		(layer "F.Cu")
		(net "M_C_CPU1_SB_DQ<12>")
	)
	(segment
		(start 28.977844 -216.441782)
		(end 29.402786 -216.866724)
		(width 0.20066)
		(layer "F.Cu")
		(net "M_C_CPU1_SB_DQ<12>")
	)
	(segment
		(start 95.193612 -237.133638)
		(end 95.193612 -236.597952)
		(width 0.20066)
		(layer "F.Cu")
		(net "M_C_CPU1_SB_DQ<12>")
	)
	(segment
		(start 25.432512 -216.932764)
		(end 25.432512 -216.643204)
		(width 0.20066)
		(layer "F.Cu")
		(net "M_C_CPU1_SB_DQ<12>")
	)
	(segment
		(start 24.801068 -217.105484)
		(end 25.259792 -217.105484)
		(width 0.20066)
		(layer "F.Cu")
		(net "M_C_CPU1_SB_DQ<12>")
	)
	(segment
		(start 25.259792 -217.105484)
		(end 25.432512 -216.932764)
		(width 0.20066)
		(layer "F.Cu")
		(net "M_C_CPU1_SB_DQ<12>")
	)
	(segment
		(start 29.402786 -216.866724)
		(end 30.771846 -216.866724)
		(width 0.20066)
		(layer "F.Cu")
		(net "M_C_CPU1_SB_DQ<12>")
	)
	(segment
		(start 25.432512 -216.643204)
		(end 25.642062 -216.433654)
		(width 0.20066)
		(layer "F.Cu")
		(net "M_C_CPU1_SB_DQ<12>")
	)
	(segment
		(start 26.459942 -216.441782)
		(end 28.529026 -216.441782)
		(width 0.1016)
		(layer "F.Cu")
		(net "M_C_CPU1_SB_DQ<12>")
	)
	(segment
		(start 95.193866 -237.133892)
		(end 95.193612 -237.133638)
		(width 0.20066)
		(layer "F.Cu")
		(net "M_C_CPU1_SB_DQ<12>")
	)
	(segment
		(start 31.876746 -216.866724)
		(end 30.771846 -216.866724)
		(width 0.20066)
		(layer "F.Cu")
		(net "M_C_CPU1_SB_DQ<12>")
	)
	(segment
		(start 55.114698 -219.841064)
		(end 50.322226 -219.841064)
		(width 0.18288)
		(layer "In6.Cu")
		(net "M_C_CPU1_SB_DQ<12>")
	)
	(segment
		(start 39.934134 -217.291412)
		(end 39.923212 -217.291412)
		(width 0.18288)
		(layer "In6.Cu")
		(net "M_C_CPU1_SB_DQ<12>")
	)
	(segment
		(start 64.336168 -222.222568)
		(end 62.81801 -220.70441)
		(width 0.18288)
		(layer "In6.Cu")
		(net "M_C_CPU1_SB_DQ<12>")
	)
	(segment
		(start 61.837824 -220.70441)
		(end 60.07227 -218.938856)
		(width 0.18288)
		(layer "In6.Cu")
		(net "M_C_CPU1_SB_DQ<12>")
	)
	(segment
		(start 62.81801 -220.70441)
		(end 61.837824 -220.70441)
		(width 0.18288)
		(layer "In6.Cu")
		(net "M_C_CPU1_SB_DQ<12>")
	)
	(segment
		(start 66.289682 -222.222568)
		(end 64.336168 -222.222568)
		(width 0.18288)
		(layer "In6.Cu")
		(net "M_C_CPU1_SB_DQ<12>")
	)
	(segment
		(start 48.622966 -218.141804)
		(end 46.707298 -218.141804)
		(width 0.18288)
		(layer "In6.Cu")
		(net "M_C_CPU1_SB_DQ<12>")
	)
	(segment
		(start 32.300926 -217.290904)
		(end 31.876746 -216.866724)
		(width 0.18288)
		(layer "In6.Cu")
		(net "M_C_CPU1_SB_DQ<12>")
	)
	(segment
		(start 89.367614 -236.273594)
		(end 89.3572 -236.27969)
		(width 0.088646)
		(layer "In6.Cu")
		(net "M_C_CPU1_SB_DQ<12>")
	)
	(segment
		(start 83.128358 -233.894884)
		(end 82.632296 -233.894884)
		(width 0.088646)
		(layer "In6.Cu")
		(net "M_C_CPU1_SB_DQ<12>")
	)
	(segment
		(start 41.991534 -218.000834)
		(end 40.643556 -218.000834)
		(width 0.18288)
		(layer "In6.Cu")
		(net "M_C_CPU1_SB_DQ<12>")
	)
	(segment
		(start 40.643556 -218.000834)
		(end 39.934134 -217.291412)
		(width 0.18288)
		(layer "In6.Cu")
		(net "M_C_CPU1_SB_DQ<12>")
	)
	(segment
		(start 45.988986 -218.860116)
		(end 42.850816 -218.860116)
		(width 0.18288)
		(layer "In6.Cu")
		(net "M_C_CPU1_SB_DQ<12>")
	)
	(segment
		(start 82.632296 -233.894884)
		(end 75.314556 -233.894884)
		(width 0.18288)
		(layer "In6.Cu")
		(net "M_C_CPU1_SB_DQ<12>")
	)
	(segment
		(start 83.297776 -234.064302)
		(end 83.128358 -233.894884)
		(width 0.088646)
		(layer "In6.Cu")
		(net "M_C_CPU1_SB_DQ<12>")
	)
	(segment
		(start 86.452964 -235.459778)
		(end 86.444582 -235.454952)
		(width 0.088646)
		(layer "In6.Cu")
		(net "M_C_CPU1_SB_DQ<12>")
	)
	(segment
		(start 93.126814 -236.273594)
		(end 93.112082 -236.28223)
		(width 0.088646)
		(layer "In6.Cu")
		(net "M_C_CPU1_SB_DQ<12>")
	)
	(segment
		(start 46.707298 -218.141804)
		(end 45.988986 -218.860116)
		(width 0.18288)
		(layer "In6.Cu")
		(net "M_C_CPU1_SB_DQ<12>")
	)
	(segment
		(start 57.073546 -219.750386)
		(end 56.890666 -219.567506)
		(width 0.18288)
		(layer "In6.Cu")
		(net "M_C_CPU1_SB_DQ<12>")
	)
	(segment
		(start 56.707786 -218.938856)
		(end 56.016906 -218.938856)
		(width 0.18288)
		(layer "In6.Cu")
		(net "M_C_CPU1_SB_DQ<12>")
	)
	(segment
		(start 86.456266 -235.461556)
		(end 86.452964 -235.459778)
		(width 0.088646)
		(layer "In6.Cu")
		(net "M_C_CPU1_SB_DQ<12>")
	)
	(segment
		(start 42.850816 -218.860116)
		(end 41.991534 -218.000834)
		(width 0.18288)
		(layer "In6.Cu")
		(net "M_C_CPU1_SB_DQ<12>")
	)
	(segment
		(start 86.640416 -235.794042)
		(end 86.640416 -235.784136)
		(width 0.088646)
		(layer "In6.Cu")
		(net "M_C_CPU1_SB_DQ<12>")
	)
	(segment
		(start 50.322226 -219.841064)
		(end 48.622966 -218.141804)
		(width 0.18288)
		(layer "In6.Cu")
		(net "M_C_CPU1_SB_DQ<12>")
	)
	(segment
		(start 83.533742 -234.761532)
		(end 83.533742 -234.634024)
		(width 0.088646)
		(layer "In6.Cu")
		(net "M_C_CPU1_SB_DQ<12>")
	)
	(segment
		(start 75.314556 -233.894884)
		(end 69.108828 -227.689156)
		(width 0.18288)
		(layer "In6.Cu")
		(net "M_C_CPU1_SB_DQ<12>")
	)
	(segment
		(start 56.890666 -219.567506)
		(end 56.890666 -219.121736)
		(width 0.18288)
		(layer "In6.Cu")
		(net "M_C_CPU1_SB_DQ<12>")
	)
	(segment
		(start 57.398666 -219.750386)
		(end 57.073546 -219.750386)
		(width 0.18288)
		(layer "In6.Cu")
		(net "M_C_CPU1_SB_DQ<12>")
	)
	(segment
		(start 94.066868 -236.273594)
		(end 94.056454 -236.27969)
		(width 0.088646)
		(layer "In6.Cu")
		(net "M_C_CPU1_SB_DQ<12>")
	)
	(segment
		(start 39.923212 -217.291412)
		(end 39.922704 -217.290904)
		(width 0.18288)
		(layer "In6.Cu")
		(net "M_C_CPU1_SB_DQ<12>")
	)
	(segment
		(start 57.581546 -219.567506)
		(end 57.398666 -219.750386)
		(width 0.18288)
		(layer "In6.Cu")
		(net "M_C_CPU1_SB_DQ<12>")
	)
	(segment
		(start 90.307414 -236.273594)
		(end 90.292682 -236.28223)
		(width 0.088646)
		(layer "In6.Cu")
		(net "M_C_CPU1_SB_DQ<12>")
	)
	(segment
		(start 39.922704 -217.290904)
		(end 32.300926 -217.290904)
		(width 0.18288)
		(layer "In6.Cu")
		(net "M_C_CPU1_SB_DQ<12>")
	)
	(segment
		(start 56.016906 -218.938856)
		(end 55.114698 -219.841064)
		(width 0.18288)
		(layer "In6.Cu")
		(net "M_C_CPU1_SB_DQ<12>")
	)
	(segment
		(start 69.108828 -225.041714)
		(end 66.289682 -222.222568)
		(width 0.18288)
		(layer "In6.Cu")
		(net "M_C_CPU1_SB_DQ<12>")
	)
	(segment
		(start 85.513418 -235.459778)
		(end 85.505036 -235.454952)
		(width 0.088646)
		(layer "In6.Cu")
		(net "M_C_CPU1_SB_DQ<12>")
	)
	(segment
		(start 57.764426 -218.938856)
		(end 57.581546 -219.121736)
		(width 0.18288)
		(layer "In6.Cu")
		(net "M_C_CPU1_SB_DQ<12>")
	)
	(segment
		(start 60.07227 -218.938856)
		(end 57.764426 -218.938856)
		(width 0.18288)
		(layer "In6.Cu")
		(net "M_C_CPU1_SB_DQ<12>")
	)
	(segment
		(start 56.890666 -219.121736)
		(end 56.707786 -218.938856)
		(width 0.18288)
		(layer "In6.Cu")
		(net "M_C_CPU1_SB_DQ<12>")
	)
	(segment
		(start 92.187014 -236.273594)
		(end 92.172282 -236.28223)
		(width 0.088646)
		(layer "In6.Cu")
		(net "M_C_CPU1_SB_DQ<12>")
	)
	(segment
		(start 69.108828 -227.689156)
		(end 69.108828 -225.041714)
		(width 0.18288)
		(layer "In6.Cu")
		(net "M_C_CPU1_SB_DQ<12>")
	)
	(segment
		(start 84.385912 -235.409232)
		(end 84.181442 -235.409232)
		(width 0.088646)
		(layer "In6.Cu")
		(net "M_C_CPU1_SB_DQ<12>")
	)
	(segment
		(start 83.533742 -234.634024)
		(end 83.297776 -234.064302)
		(width 0.088646)
		(layer "In6.Cu")
		(net "M_C_CPU1_SB_DQ<12>")
	)
	(segment
		(start 84.181442 -235.409232)
		(end 83.533742 -234.761532)
		(width 0.088646)
		(layer "In6.Cu")
		(net "M_C_CPU1_SB_DQ<12>")
	)
	(segment
		(start 57.581546 -219.121736)
		(end 57.581546 -219.567506)
		(width 0.18288)
		(layer "In6.Cu")
		(net "M_C_CPU1_SB_DQ<12>")
	)
	(arc
		(start 87.488268 -236.273594)
		(mid 87.205566 -236.34937)
		(end 86.922864 -236.273594)
		(width 0.088646)
		(layer "In6.Cu")
		(net "M_C_CPU1_SB_DQ<12>")
	)
	(arc
		(start 85.138768 -235.459778)
		(mid 84.861955 -235.535648)
		(end 84.583524 -235.465874)
		(width 0.088646)
		(layer "In6.Cu")
		(net "M_C_CPU1_SB_DQ<12>")
	)
	(arc
		(start 87.862664 -236.273594)
		(mid 87.675466 -236.223451)
		(end 87.488268 -236.273594)
		(width 0.088646)
		(layer "In6.Cu")
		(net "M_C_CPU1_SB_DQ<12>")
	)
	(arc
		(start 85.505036 -235.454952)
		(mid 85.321274 -235.409552)
		(end 85.138768 -235.459778)
		(width 0.088646)
		(layer "In6.Cu")
		(net "M_C_CPU1_SB_DQ<12>")
	)
	(arc
		(start 92.56141 -236.273594)
		(mid 92.374212 -236.223451)
		(end 92.187014 -236.273594)
		(width 0.088646)
		(layer "In6.Cu")
		(net "M_C_CPU1_SB_DQ<12>")
	)
	(arc
		(start 88.428068 -236.273594)
		(mid 88.145366 -236.349336)
		(end 87.862664 -236.273594)
		(width 0.088646)
		(layer "In6.Cu")
		(net "M_C_CPU1_SB_DQ<12>")
	)
	(arc
		(start 94.441264 -236.273594)
		(mid 94.254066 -236.223451)
		(end 94.066868 -236.273594)
		(width 0.088646)
		(layer "In6.Cu")
		(net "M_C_CPU1_SB_DQ<12>")
	)
	(arc
		(start 86.922864 -236.273594)
		(mid 86.718529 -236.070989)
		(end 86.640416 -235.794042)
		(width 0.088646)
		(layer "In6.Cu")
		(net "M_C_CPU1_SB_DQ<12>")
	)
	(arc
		(start 84.583524 -235.465874)
		(mid 84.48868 -235.423723)
		(end 84.385912 -235.409232)
		(width 0.088646)
		(layer "In6.Cu")
		(net "M_C_CPU1_SB_DQ<12>")
	)
	(arc
		(start 95.193612 -236.597952)
		(mid 94.807986 -236.457696)
		(end 94.441264 -236.273594)
		(width 0.088646)
		(layer "In6.Cu")
		(net "M_C_CPU1_SB_DQ<12>")
	)
	(arc
		(start 86.078822 -235.459778)
		(mid 85.79612 -235.535554)
		(end 85.513418 -235.459778)
		(width 0.088646)
		(layer "In6.Cu")
		(net "M_C_CPU1_SB_DQ<12>")
	)
	(arc
		(start 93.50121 -236.273594)
		(mid 93.314012 -236.223451)
		(end 93.126814 -236.273594)
		(width 0.088646)
		(layer "In6.Cu")
		(net "M_C_CPU1_SB_DQ<12>")
	)
	(arc
		(start 90.292682 -236.28223)
		(mid 90.016241 -236.349396)
		(end 89.74201 -236.273594)
		(width 0.088646)
		(layer "In6.Cu")
		(net "M_C_CPU1_SB_DQ<12>")
	)
	(arc
		(start 86.640416 -235.784136)
		(mid 86.591141 -235.59841)
		(end 86.456266 -235.461556)
		(width 0.088646)
		(layer "In6.Cu")
		(net "M_C_CPU1_SB_DQ<12>")
	)
	(arc
		(start 89.74201 -236.273594)
		(mid 89.554812 -236.223451)
		(end 89.367614 -236.273594)
		(width 0.088646)
		(layer "In6.Cu")
		(net "M_C_CPU1_SB_DQ<12>")
	)
	(arc
		(start 91.62161 -236.273594)
		(mid 91.434412 -236.223451)
		(end 91.247214 -236.273594)
		(width 0.088646)
		(layer "In6.Cu")
		(net "M_C_CPU1_SB_DQ<12>")
	)
	(arc
		(start 91.247214 -236.273594)
		(mid 90.964512 -236.349336)
		(end 90.68181 -236.273594)
		(width 0.088646)
		(layer "In6.Cu")
		(net "M_C_CPU1_SB_DQ<12>")
	)
	(arc
		(start 86.444582 -235.454952)
		(mid 86.261074 -235.409674)
		(end 86.078822 -235.459778)
		(width 0.088646)
		(layer "In6.Cu")
		(net "M_C_CPU1_SB_DQ<12>")
	)
	(arc
		(start 90.68181 -236.273594)
		(mid 90.494612 -236.223451)
		(end 90.307414 -236.273594)
		(width 0.088646)
		(layer "In6.Cu")
		(net "M_C_CPU1_SB_DQ<12>")
	)
	(arc
		(start 93.112082 -236.28223)
		(mid 92.835641 -236.349396)
		(end 92.56141 -236.273594)
		(width 0.088646)
		(layer "In6.Cu")
		(net "M_C_CPU1_SB_DQ<12>")
	)
	(arc
		(start 92.172282 -236.28223)
		(mid 91.895841 -236.349396)
		(end 91.62161 -236.273594)
		(width 0.088646)
		(layer "In6.Cu")
		(net "M_C_CPU1_SB_DQ<12>")
	)
	(arc
		(start 89.3572 -236.27969)
		(mid 89.079022 -236.349382)
		(end 88.802464 -236.273594)
		(width 0.088646)
		(layer "In6.Cu")
		(net "M_C_CPU1_SB_DQ<12>")
	)
	(arc
		(start 94.056454 -236.27969)
		(mid 93.778022 -236.349504)
		(end 93.50121 -236.273594)
		(width 0.088646)
		(layer "In6.Cu")
		(net "M_C_CPU1_SB_DQ<12>")
	)
	(arc
		(start 88.802464 -236.273594)
		(mid 88.615266 -236.223451)
		(end 88.428068 -236.273594)
		(width 0.088646)
		(layer "In6.Cu")
		(net "M_C_CPU1_SB_DQ<12>")
	)
	(segment
		(start 33.848294 -220.474286)
		(end 34.055812 -220.266768)
		(width 0.20066)
		(layer "F.Cu")
		(net "M_C_CPU1_SB_DQ<11>")
	)
	(segment
		(start 29.025342 -220.266768)
		(end 29.151326 -220.392752)
		(width 0.20066)
		(layer "F.Cu")
		(net "M_C_CPU1_SB_DQ<11>")
	)
	(segment
		(start 97.073212 -238.76127)
		(end 97.073212 -238.225584)
		(width 0.20066)
		(layer "F.Cu")
		(net "M_C_CPU1_SB_DQ<11>")
	)
	(segment
		(start 29.151326 -220.392752)
		(end 29.151326 -220.56344)
		(width 0.20066)
		(layer "F.Cu")
		(net "M_C_CPU1_SB_DQ<11>")
	)
	(segment
		(start 32.51708 -220.69171)
		(end 32.666178 -220.542612)
		(width 0.20066)
		(layer "F.Cu")
		(net "M_C_CPU1_SB_DQ<11>")
	)
	(segment
		(start 32.794702 -220.26245)
		(end 33.189926 -220.26245)
		(width 0.20066)
		(layer "F.Cu")
		(net "M_C_CPU1_SB_DQ<11>")
	)
	(segment
		(start 29.647642 -220.705934)
		(end 29.661866 -220.69171)
		(width 0.101854)
		(layer "F.Cu")
		(net "M_C_CPU1_SB_DQ<11>")
	)
	(segment
		(start 27.328114 -220.266768)
		(end 29.025342 -220.266768)
		(width 0.20066)
		(layer "F.Cu")
		(net "M_C_CPU1_SB_DQ<11>")
	)
	(segment
		(start 32.666178 -220.542612)
		(end 32.666178 -220.390974)
		(width 0.20066)
		(layer "F.Cu")
		(net "M_C_CPU1_SB_DQ<11>")
	)
	(segment
		(start 29.151326 -220.56344)
		(end 29.29382 -220.705934)
		(width 0.20066)
		(layer "F.Cu")
		(net "M_C_CPU1_SB_DQ<11>")
	)
	(segment
		(start 29.29382 -220.705934)
		(end 29.647642 -220.705934)
		(width 0.20066)
		(layer "F.Cu")
		(net "M_C_CPU1_SB_DQ<11>")
	)
	(segment
		(start 97.073466 -238.761524)
		(end 97.073212 -238.76127)
		(width 0.20066)
		(layer "F.Cu")
		(net "M_C_CPU1_SB_DQ<11>")
	)
	(segment
		(start 32.666178 -220.390974)
		(end 32.794702 -220.26245)
		(width 0.20066)
		(layer "F.Cu")
		(net "M_C_CPU1_SB_DQ<11>")
	)
	(segment
		(start 33.189926 -220.26245)
		(end 33.401762 -220.474286)
		(width 0.20066)
		(layer "F.Cu")
		(net "M_C_CPU1_SB_DQ<11>")
	)
	(segment
		(start 31.972758 -220.69171)
		(end 32.51708 -220.69171)
		(width 0.20066)
		(layer "F.Cu")
		(net "M_C_CPU1_SB_DQ<11>")
	)
	(segment
		(start 34.055812 -220.266768)
		(end 34.871914 -220.266768)
		(width 0.20066)
		(layer "F.Cu")
		(net "M_C_CPU1_SB_DQ<11>")
	)
	(segment
		(start 35.976814 -220.266768)
		(end 34.871914 -220.266768)
		(width 0.20066)
		(layer "F.Cu")
		(net "M_C_CPU1_SB_DQ<11>")
	)
	(segment
		(start 29.899864 -220.69171)
		(end 31.972758 -220.69171)
		(width 0.1016)
		(layer "F.Cu")
		(net "M_C_CPU1_SB_DQ<11>")
	)
	(segment
		(start 29.661866 -220.69171)
		(end 29.899864 -220.69171)
		(width 0.101854)
		(layer "F.Cu")
		(net "M_C_CPU1_SB_DQ<11>")
	)
	(segment
		(start 33.401762 -220.474286)
		(end 33.848294 -220.474286)
		(width 0.20066)
		(layer "F.Cu")
		(net "M_C_CPU1_SB_DQ<11>")
	)
	(segment
		(start 89.367614 -238.549942)
		(end 89.352882 -238.541306)
		(width 0.088646)
		(layer "In6.Cu")
		(net "M_C_CPU1_SB_DQ<11>")
	)
	(segment
		(start 58.137044 -223.491298)
		(end 58.137044 -223.90862)
		(width 0.18288)
		(layer "In6.Cu")
		(net "M_C_CPU1_SB_DQ<11>")
	)
	(segment
		(start 53.780436 -223.679004)
		(end 53.597556 -223.496124)
		(width 0.18288)
		(layer "In6.Cu")
		(net "M_C_CPU1_SB_DQ<11>")
	)
	(segment
		(start 63.33998 -225.91395)
		(end 62.367414 -224.941384)
		(width 0.18288)
		(layer "In6.Cu")
		(net "M_C_CPU1_SB_DQ<11>")
	)
	(segment
		(start 65.68567 -227.595938)
		(end 65.081912 -226.99218)
		(width 0.18288)
		(layer "In6.Cu")
		(net "M_C_CPU1_SB_DQ<11>")
	)
	(segment
		(start 38.013894 -220.109288)
		(end 37.831014 -220.292168)
		(width 0.18288)
		(layer "In6.Cu")
		(net "M_C_CPU1_SB_DQ<11>")
	)
	(segment
		(start 36.466272 -220.756226)
		(end 35.976814 -220.266768)
		(width 0.18288)
		(layer "In6.Cu")
		(net "M_C_CPU1_SB_DQ<11>")
	)
	(segment
		(start 57.446164 -223.491298)
		(end 57.263284 -223.308418)
		(width 0.18288)
		(layer "In6.Cu")
		(net "M_C_CPU1_SB_DQ<11>")
	)
	(segment
		(start 90.307414 -238.549942)
		(end 90.292682 -238.541306)
		(width 0.088646)
		(layer "In6.Cu")
		(net "M_C_CPU1_SB_DQ<11>")
	)
	(segment
		(start 95.01251 -237.89767)
		(end 94.991682 -237.909862)
		(width 0.088646)
		(layer "In6.Cu")
		(net "M_C_CPU1_SB_DQ<11>")
	)
	(segment
		(start 88.427814 -238.549942)
		(end 88.4174 -238.543846)
		(width 0.088646)
		(layer "In6.Cu")
		(net "M_C_CPU1_SB_DQ<11>")
	)
	(segment
		(start 38.339014 -220.109288)
		(end 38.013894 -220.109288)
		(width 0.18288)
		(layer "In6.Cu")
		(net "M_C_CPU1_SB_DQ<11>")
	)
	(segment
		(start 60.146438 -224.941384)
		(end 59.296554 -224.0915)
		(width 0.18288)
		(layer "In6.Cu")
		(net "M_C_CPU1_SB_DQ<11>")
	)
	(segment
		(start 53.272436 -223.496124)
		(end 53.089556 -223.679004)
		(width 0.18288)
		(layer "In6.Cu")
		(net "M_C_CPU1_SB_DQ<11>")
	)
	(segment
		(start 92.187014 -238.549942)
		(end 92.1766 -238.543846)
		(width 0.088646)
		(layer "In6.Cu")
		(net "M_C_CPU1_SB_DQ<11>")
	)
	(segment
		(start 45.191172 -222.391732)
		(end 42.388028 -222.391732)
		(width 0.18288)
		(layer "In6.Cu")
		(net "M_C_CPU1_SB_DQ<11>")
	)
	(segment
		(start 56.247284 -224.0915)
		(end 56.064404 -223.90862)
		(width 0.18288)
		(layer "In6.Cu")
		(net "M_C_CPU1_SB_DQ<11>")
	)
	(segment
		(start 66.38417 -228.342952)
		(end 65.953132 -228.342952)
		(width 0.18288)
		(layer "In6.Cu")
		(net "M_C_CPU1_SB_DQ<11>")
	)
	(segment
		(start 85.99805 -238.541306)
		(end 85.983318 -238.549942)
		(width 0.088646)
		(layer "In6.Cu")
		(net "M_C_CPU1_SB_DQ<11>")
	)
	(segment
		(start 58.137044 -223.90862)
		(end 57.954164 -224.0915)
		(width 0.18288)
		(layer "In6.Cu")
		(net "M_C_CPU1_SB_DQ<11>")
	)
	(segment
		(start 53.089556 -223.90862)
		(end 52.906676 -224.0915)
		(width 0.18288)
		(layer "In6.Cu")
		(net "M_C_CPU1_SB_DQ<11>")
	)
	(segment
		(start 82.835496 -236.013752)
		(end 74.05497 -236.013752)
		(width 0.18288)
		(layer "In6.Cu")
		(net "M_C_CPU1_SB_DQ<11>")
	)
	(segment
		(start 94.066614 -238.549942)
		(end 94.051882 -238.541306)
		(width 0.088646)
		(layer "In6.Cu")
		(net "M_C_CPU1_SB_DQ<11>")
	)
	(segment
		(start 83.206336 -236.164882)
		(end 83.055206 -236.013752)
		(width 0.088646)
		(layer "In6.Cu")
		(net "M_C_CPU1_SB_DQ<11>")
	)
	(segment
		(start 55.556404 -223.308418)
		(end 55.373524 -223.491298)
		(width 0.18288)
		(layer "In6.Cu")
		(net "M_C_CPU1_SB_DQ<11>")
	)
	(segment
		(start 83.761326 -237.656624)
		(end 83.761326 -237.202218)
		(width 0.088646)
		(layer "In6.Cu")
		(net "M_C_CPU1_SB_DQ<11>")
	)
	(segment
		(start 38.521894 -220.292168)
		(end 38.339014 -220.109288)
		(width 0.18288)
		(layer "In6.Cu")
		(net "M_C_CPU1_SB_DQ<11>")
	)
	(segment
		(start 38.521894 -220.573346)
		(end 38.521894 -220.292168)
		(width 0.18288)
		(layer "In6.Cu")
		(net "M_C_CPU1_SB_DQ<11>")
	)
	(segment
		(start 52.906676 -224.0915)
		(end 50.091086 -224.0915)
		(width 0.18288)
		(layer "In6.Cu")
		(net "M_C_CPU1_SB_DQ<11>")
	)
	(segment
		(start 65.953132 -228.342952)
		(end 65.68567 -228.07549)
		(width 0.18288)
		(layer "In6.Cu")
		(net "M_C_CPU1_SB_DQ<11>")
	)
	(segment
		(start 83.761326 -237.202218)
		(end 83.29295 -236.733842)
		(width 0.088646)
		(layer "In6.Cu")
		(net "M_C_CPU1_SB_DQ<11>")
	)
	(segment
		(start 55.190644 -224.0915)
		(end 53.963316 -224.0915)
		(width 0.18288)
		(layer "In6.Cu")
		(net "M_C_CPU1_SB_DQ<11>")
	)
	(segment
		(start 85.144864 -237.739682)
		(end 85.138768 -237.736126)
		(width 0.088646)
		(layer "In6.Cu")
		(net "M_C_CPU1_SB_DQ<11>")
	)
	(segment
		(start 37.648134 -220.756226)
		(end 36.466272 -220.756226)
		(width 0.18288)
		(layer "In6.Cu")
		(net "M_C_CPU1_SB_DQ<11>")
	)
	(segment
		(start 56.064404 -223.90862)
		(end 56.064404 -223.491298)
		(width 0.18288)
		(layer "In6.Cu")
		(net "M_C_CPU1_SB_DQ<11>")
	)
	(segment
		(start 85.138768 -237.736126)
		(end 85.124036 -237.72749)
		(width 0.088646)
		(layer "In6.Cu")
		(net "M_C_CPU1_SB_DQ<11>")
	)
	(segment
		(start 53.089556 -223.679004)
		(end 53.089556 -223.90862)
		(width 0.18288)
		(layer "In6.Cu")
		(net "M_C_CPU1_SB_DQ<11>")
	)
	(segment
		(start 96.718628 -238.130588)
		(end 96.315022 -237.89767)
		(width 0.088646)
		(layer "In6.Cu")
		(net "M_C_CPU1_SB_DQ<11>")
	)
	(segment
		(start 55.373524 -223.90862)
		(end 55.190644 -224.0915)
		(width 0.18288)
		(layer "In6.Cu")
		(net "M_C_CPU1_SB_DQ<11>")
	)
	(segment
		(start 46.041056 -223.241616)
		(end 45.191172 -222.391732)
		(width 0.18288)
		(layer "In6.Cu")
		(net "M_C_CPU1_SB_DQ<11>")
	)
	(segment
		(start 74.05497 -236.013752)
		(end 66.38417 -228.342952)
		(width 0.18288)
		(layer "In6.Cu")
		(net "M_C_CPU1_SB_DQ<11>")
	)
	(segment
		(start 57.446164 -223.90862)
		(end 57.446164 -223.491298)
		(width 0.18288)
		(layer "In6.Cu")
		(net "M_C_CPU1_SB_DQ<11>")
	)
	(segment
		(start 57.954164 -224.0915)
		(end 57.629044 -224.0915)
		(width 0.18288)
		(layer "In6.Cu")
		(net "M_C_CPU1_SB_DQ<11>")
	)
	(segment
		(start 50.091086 -224.0915)
		(end 49.241202 -223.241616)
		(width 0.18288)
		(layer "In6.Cu")
		(net "M_C_CPU1_SB_DQ<11>")
	)
	(segment
		(start 58.319924 -223.308418)
		(end 58.137044 -223.491298)
		(width 0.18288)
		(layer "In6.Cu")
		(net "M_C_CPU1_SB_DQ<11>")
	)
	(segment
		(start 85.608922 -238.549942)
		(end 85.600032 -238.544862)
		(width 0.088646)
		(layer "In6.Cu")
		(net "M_C_CPU1_SB_DQ<11>")
	)
	(segment
		(start 83.206336 -236.406182)
		(end 83.206336 -236.164882)
		(width 0.088646)
		(layer "In6.Cu")
		(net "M_C_CPU1_SB_DQ<11>")
	)
	(segment
		(start 93.126814 -238.549942)
		(end 93.112082 -238.541306)
		(width 0.088646)
		(layer "In6.Cu")
		(net "M_C_CPU1_SB_DQ<11>")
	)
	(segment
		(start 83.29295 -236.492796)
		(end 83.206336 -236.406182)
		(width 0.088646)
		(layer "In6.Cu")
		(net "M_C_CPU1_SB_DQ<11>")
	)
	(segment
		(start 62.367414 -224.941384)
		(end 60.146438 -224.941384)
		(width 0.18288)
		(layer "In6.Cu")
		(net "M_C_CPU1_SB_DQ<11>")
	)
	(segment
		(start 57.263284 -223.308418)
		(end 56.938164 -223.308418)
		(width 0.18288)
		(layer "In6.Cu")
		(net "M_C_CPU1_SB_DQ<11>")
	)
	(segment
		(start 41.631108 -221.634812)
		(end 41.205912 -221.634812)
		(width 0.18288)
		(layer "In6.Cu")
		(net "M_C_CPU1_SB_DQ<11>")
	)
	(segment
		(start 63.33998 -226.512374)
		(end 63.33998 -225.91395)
		(width 0.18288)
		(layer "In6.Cu")
		(net "M_C_CPU1_SB_DQ<11>")
	)
	(segment
		(start 59.010804 -224.0915)
		(end 58.827924 -223.90862)
		(width 0.18288)
		(layer "In6.Cu")
		(net "M_C_CPU1_SB_DQ<11>")
	)
	(segment
		(start 53.963316 -224.0915)
		(end 53.780436 -223.90862)
		(width 0.18288)
		(layer "In6.Cu")
		(net "M_C_CPU1_SB_DQ<11>")
	)
	(segment
		(start 56.938164 -223.308418)
		(end 56.755284 -223.491298)
		(width 0.18288)
		(layer "In6.Cu")
		(net "M_C_CPU1_SB_DQ<11>")
	)
	(segment
		(start 91.247468 -238.549942)
		(end 91.237054 -238.543846)
		(width 0.088646)
		(layer "In6.Cu")
		(net "M_C_CPU1_SB_DQ<11>")
	)
	(segment
		(start 37.831014 -220.573346)
		(end 37.648134 -220.756226)
		(width 0.18288)
		(layer "In6.Cu")
		(net "M_C_CPU1_SB_DQ<11>")
	)
	(segment
		(start 55.881524 -223.308418)
		(end 55.556404 -223.308418)
		(width 0.18288)
		(layer "In6.Cu")
		(net "M_C_CPU1_SB_DQ<11>")
	)
	(segment
		(start 53.780436 -223.90862)
		(end 53.780436 -223.679004)
		(width 0.18288)
		(layer "In6.Cu")
		(net "M_C_CPU1_SB_DQ<11>")
	)
	(segment
		(start 65.081912 -226.99218)
		(end 63.819786 -226.99218)
		(width 0.18288)
		(layer "In6.Cu")
		(net "M_C_CPU1_SB_DQ<11>")
	)
	(segment
		(start 37.831014 -220.292168)
		(end 37.831014 -220.573346)
		(width 0.18288)
		(layer "In6.Cu")
		(net "M_C_CPU1_SB_DQ<11>")
	)
	(segment
		(start 59.296554 -224.0915)
		(end 59.010804 -224.0915)
		(width 0.18288)
		(layer "In6.Cu")
		(net "M_C_CPU1_SB_DQ<11>")
	)
	(segment
		(start 63.819786 -226.99218)
		(end 63.33998 -226.512374)
		(width 0.18288)
		(layer "In6.Cu")
		(net "M_C_CPU1_SB_DQ<11>")
	)
	(segment
		(start 84.385912 -237.786926)
		(end 83.891628 -237.786926)
		(width 0.088646)
		(layer "In6.Cu")
		(net "M_C_CPU1_SB_DQ<11>")
	)
	(segment
		(start 56.572404 -224.0915)
		(end 56.247284 -224.0915)
		(width 0.18288)
		(layer "In6.Cu")
		(net "M_C_CPU1_SB_DQ<11>")
	)
	(segment
		(start 41.205912 -221.634812)
		(end 40.327326 -220.756226)
		(width 0.18288)
		(layer "In6.Cu")
		(net "M_C_CPU1_SB_DQ<11>")
	)
	(segment
		(start 83.891628 -237.786926)
		(end 83.761326 -237.656624)
		(width 0.088646)
		(layer "In6.Cu")
		(net "M_C_CPU1_SB_DQ<11>")
	)
	(segment
		(start 86.933532 -238.543846)
		(end 86.923118 -238.549942)
		(width 0.088646)
		(layer "In6.Cu")
		(net "M_C_CPU1_SB_DQ<11>")
	)
	(segment
		(start 58.827924 -223.491298)
		(end 58.645044 -223.308418)
		(width 0.18288)
		(layer "In6.Cu")
		(net "M_C_CPU1_SB_DQ<11>")
	)
	(segment
		(start 65.68567 -228.07549)
		(end 65.68567 -227.595938)
		(width 0.18288)
		(layer "In6.Cu")
		(net "M_C_CPU1_SB_DQ<11>")
	)
	(segment
		(start 56.755284 -223.90862)
		(end 56.572404 -224.0915)
		(width 0.18288)
		(layer "In6.Cu")
		(net "M_C_CPU1_SB_DQ<11>")
	)
	(segment
		(start 40.327326 -220.756226)
		(end 38.704774 -220.756226)
		(width 0.18288)
		(layer "In6.Cu")
		(net "M_C_CPU1_SB_DQ<11>")
	)
	(segment
		(start 57.629044 -224.0915)
		(end 57.446164 -223.90862)
		(width 0.18288)
		(layer "In6.Cu")
		(net "M_C_CPU1_SB_DQ<11>")
	)
	(segment
		(start 38.704774 -220.756226)
		(end 38.521894 -220.573346)
		(width 0.18288)
		(layer "In6.Cu")
		(net "M_C_CPU1_SB_DQ<11>")
	)
	(segment
		(start 83.055206 -236.013752)
		(end 82.835496 -236.013752)
		(width 0.088646)
		(layer "In6.Cu")
		(net "M_C_CPU1_SB_DQ<11>")
	)
	(segment
		(start 56.755284 -223.491298)
		(end 56.755284 -223.90862)
		(width 0.18288)
		(layer "In6.Cu")
		(net "M_C_CPU1_SB_DQ<11>")
	)
	(segment
		(start 83.29295 -236.733842)
		(end 83.29295 -236.492796)
		(width 0.088646)
		(layer "In6.Cu")
		(net "M_C_CPU1_SB_DQ<11>")
	)
	(segment
		(start 56.064404 -223.491298)
		(end 55.881524 -223.308418)
		(width 0.18288)
		(layer "In6.Cu")
		(net "M_C_CPU1_SB_DQ<11>")
	)
	(segment
		(start 58.645044 -223.308418)
		(end 58.319924 -223.308418)
		(width 0.18288)
		(layer "In6.Cu")
		(net "M_C_CPU1_SB_DQ<11>")
	)
	(segment
		(start 42.388028 -222.391732)
		(end 41.631108 -221.634812)
		(width 0.18288)
		(layer "In6.Cu")
		(net "M_C_CPU1_SB_DQ<11>")
	)
	(segment
		(start 53.597556 -223.496124)
		(end 53.272436 -223.496124)
		(width 0.18288)
		(layer "In6.Cu")
		(net "M_C_CPU1_SB_DQ<11>")
	)
	(segment
		(start 55.373524 -223.491298)
		(end 55.373524 -223.90862)
		(width 0.18288)
		(layer "In6.Cu")
		(net "M_C_CPU1_SB_DQ<11>")
	)
	(segment
		(start 58.827924 -223.90862)
		(end 58.827924 -223.491298)
		(width 0.18288)
		(layer "In6.Cu")
		(net "M_C_CPU1_SB_DQ<11>")
	)
	(segment
		(start 49.241202 -223.241616)
		(end 46.041056 -223.241616)
		(width 0.18288)
		(layer "In6.Cu")
		(net "M_C_CPU1_SB_DQ<11>")
	)
	(arc
		(start 87.862664 -238.549942)
		(mid 87.675466 -238.600085)
		(end 87.488268 -238.549942)
		(width 0.088646)
		(layer "In6.Cu")
		(net "M_C_CPU1_SB_DQ<11>")
	)
	(arc
		(start 92.56141 -238.549942)
		(mid 92.374212 -238.600085)
		(end 92.187014 -238.549942)
		(width 0.088646)
		(layer "In6.Cu")
		(net "M_C_CPU1_SB_DQ<11>")
	)
	(arc
		(start 84.573364 -237.736126)
		(mid 84.482985 -237.773881)
		(end 84.385912 -237.786926)
		(width 0.088646)
		(layer "In6.Cu")
		(net "M_C_CPU1_SB_DQ<11>")
	)
	(arc
		(start 86.548722 -238.549942)
		(mid 86.274523 -238.474107)
		(end 85.99805 -238.541306)
		(width 0.088646)
		(layer "In6.Cu")
		(net "M_C_CPU1_SB_DQ<11>")
	)
	(arc
		(start 86.923118 -238.549942)
		(mid 86.73592 -238.600085)
		(end 86.548722 -238.549942)
		(width 0.088646)
		(layer "In6.Cu")
		(net "M_C_CPU1_SB_DQ<11>")
	)
	(arc
		(start 97.073212 -238.225584)
		(mid 96.889669 -238.201421)
		(end 96.718628 -238.130588)
		(width 0.088646)
		(layer "In6.Cu")
		(net "M_C_CPU1_SB_DQ<11>")
	)
	(arc
		(start 96.315022 -237.89767)
		(mid 96.130167 -237.850752)
		(end 95.946214 -237.900972)
		(width 0.088646)
		(layer "In6.Cu")
		(net "M_C_CPU1_SB_DQ<11>")
	)
	(arc
		(start 92.1766 -238.543846)
		(mid 91.898422 -238.474123)
		(end 91.621864 -238.549942)
		(width 0.088646)
		(layer "In6.Cu")
		(net "M_C_CPU1_SB_DQ<11>")
	)
	(arc
		(start 85.124036 -237.72749)
		(mid 84.847561 -237.66017)
		(end 84.573364 -237.736126)
		(width 0.088646)
		(layer "In6.Cu")
		(net "M_C_CPU1_SB_DQ<11>")
	)
	(arc
		(start 89.74201 -238.549942)
		(mid 89.554812 -238.600085)
		(end 89.367614 -238.549942)
		(width 0.088646)
		(layer "In6.Cu")
		(net "M_C_CPU1_SB_DQ<11>")
	)
	(arc
		(start 85.42147 -238.225584)
		(mid 85.347479 -237.946018)
		(end 85.144864 -237.739682)
		(width 0.088646)
		(layer "In6.Cu")
		(net "M_C_CPU1_SB_DQ<11>")
	)
	(arc
		(start 85.600032 -238.544862)
		(mid 85.469118 -238.408502)
		(end 85.42147 -238.225584)
		(width 0.088646)
		(layer "In6.Cu")
		(net "M_C_CPU1_SB_DQ<11>")
	)
	(arc
		(start 91.621864 -238.549942)
		(mid 91.434666 -238.600085)
		(end 91.247468 -238.549942)
		(width 0.088646)
		(layer "In6.Cu")
		(net "M_C_CPU1_SB_DQ<11>")
	)
	(arc
		(start 93.50121 -238.549942)
		(mid 93.314012 -238.600085)
		(end 93.126814 -238.549942)
		(width 0.088646)
		(layer "In6.Cu")
		(net "M_C_CPU1_SB_DQ<11>")
	)
	(arc
		(start 88.4174 -238.543846)
		(mid 88.139222 -238.474123)
		(end 87.862664 -238.549942)
		(width 0.088646)
		(layer "In6.Cu")
		(net "M_C_CPU1_SB_DQ<11>")
	)
	(arc
		(start 94.991682 -237.909862)
		(mid 94.857355 -238.025295)
		(end 94.772226 -238.180626)
		(width 0.088646)
		(layer "In6.Cu")
		(net "M_C_CPU1_SB_DQ<11>")
	)
	(arc
		(start 94.772226 -238.180626)
		(mid 94.636066 -238.391692)
		(end 94.44101 -238.549942)
		(width 0.088646)
		(layer "In6.Cu")
		(net "M_C_CPU1_SB_DQ<11>")
	)
	(arc
		(start 95.946214 -237.900972)
		(mid 95.668649 -237.96159)
		(end 95.407226 -237.850426)
		(width 0.088646)
		(layer "In6.Cu")
		(net "M_C_CPU1_SB_DQ<11>")
	)
	(arc
		(start 91.237054 -238.543846)
		(mid 90.958622 -238.474)
		(end 90.68181 -238.549942)
		(width 0.088646)
		(layer "In6.Cu")
		(net "M_C_CPU1_SB_DQ<11>")
	)
	(arc
		(start 90.292682 -238.541306)
		(mid 90.016207 -238.473986)
		(end 89.74201 -238.549942)
		(width 0.088646)
		(layer "In6.Cu")
		(net "M_C_CPU1_SB_DQ<11>")
	)
	(arc
		(start 93.112082 -238.541306)
		(mid 92.835607 -238.473986)
		(end 92.56141 -238.549942)
		(width 0.088646)
		(layer "In6.Cu")
		(net "M_C_CPU1_SB_DQ<11>")
	)
	(arc
		(start 94.44101 -238.549942)
		(mid 94.253812 -238.600085)
		(end 94.066614 -238.549942)
		(width 0.088646)
		(layer "In6.Cu")
		(net "M_C_CPU1_SB_DQ<11>")
	)
	(arc
		(start 87.488268 -238.549942)
		(mid 87.211709 -238.474199)
		(end 86.933532 -238.543846)
		(width 0.088646)
		(layer "In6.Cu")
		(net "M_C_CPU1_SB_DQ<11>")
	)
	(arc
		(start 85.983318 -238.549942)
		(mid 85.79612 -238.600085)
		(end 85.608922 -238.549942)
		(width 0.088646)
		(layer "In6.Cu")
		(net "M_C_CPU1_SB_DQ<11>")
	)
	(arc
		(start 88.80221 -238.549942)
		(mid 88.615012 -238.600085)
		(end 88.427814 -238.549942)
		(width 0.088646)
		(layer "In6.Cu")
		(net "M_C_CPU1_SB_DQ<11>")
	)
	(arc
		(start 90.68181 -238.549942)
		(mid 90.494612 -238.600085)
		(end 90.307414 -238.549942)
		(width 0.088646)
		(layer "In6.Cu")
		(net "M_C_CPU1_SB_DQ<11>")
	)
	(arc
		(start 94.051882 -238.541306)
		(mid 93.775407 -238.473986)
		(end 93.50121 -238.549942)
		(width 0.088646)
		(layer "In6.Cu")
		(net "M_C_CPU1_SB_DQ<11>")
	)
	(arc
		(start 95.407226 -237.850426)
		(mid 95.204983 -237.833163)
		(end 95.01251 -237.89767)
		(width 0.088646)
		(layer "In6.Cu")
		(net "M_C_CPU1_SB_DQ<11>")
	)
	(arc
		(start 89.352882 -238.541306)
		(mid 89.076407 -238.473986)
		(end 88.80221 -238.549942)
		(width 0.088646)
		(layer "In6.Cu")
		(net "M_C_CPU1_SB_DQ<11>")
	)
	(segment
		(start 33.55721 -221.96679)
		(end 34.871914 -221.96679)
		(width 0.20066)
		(layer "F.Cu")
		(net "M_C_CPU1_SB_DQ<10>")
	)
	(segment
		(start 96.603312 -239.57534)
		(end 96.603566 -239.575086)
		(width 0.20066)
		(layer "F.Cu")
		(net "M_C_CPU1_SB_DQ<10>")
	)
	(segment
		(start 29.647642 -221.531688)
		(end 29.657802 -221.541848)
		(width 0.101854)
		(layer "F.Cu")
		(net "M_C_CPU1_SB_DQ<10>")
	)
	(segment
		(start 35.976814 -221.96679)
		(end 34.871914 -221.96679)
		(width 0.20066)
		(layer "F.Cu")
		(net "M_C_CPU1_SB_DQ<10>")
	)
	(segment
		(start 29.912818 -221.541848)
		(end 31.972758 -221.541848)
		(width 0.1016)
		(layer "F.Cu")
		(net "M_C_CPU1_SB_DQ<10>")
	)
	(segment
		(start 29.657802 -221.541848)
		(end 29.912818 -221.541848)
		(width 0.101854)
		(layer "F.Cu")
		(net "M_C_CPU1_SB_DQ<10>")
	)
	(segment
		(start 32.605726 -221.541848)
		(end 32.74949 -221.685612)
		(width 0.20066)
		(layer "F.Cu")
		(net "M_C_CPU1_SB_DQ<10>")
	)
	(segment
		(start 27.328114 -221.96679)
		(end 28.475178 -221.96679)
		(width 0.20066)
		(layer "F.Cu")
		(net "M_C_CPU1_SB_DQ<10>")
	)
	(segment
		(start 32.74949 -222.01124)
		(end 32.916876 -222.178626)
		(width 0.20066)
		(layer "F.Cu")
		(net "M_C_CPU1_SB_DQ<10>")
	)
	(segment
		(start 32.916876 -222.178626)
		(end 33.345374 -222.178626)
		(width 0.20066)
		(layer "F.Cu")
		(net "M_C_CPU1_SB_DQ<10>")
	)
	(segment
		(start 33.345374 -222.178626)
		(end 33.55721 -221.96679)
		(width 0.20066)
		(layer "F.Cu")
		(net "M_C_CPU1_SB_DQ<10>")
	)
	(segment
		(start 28.475178 -221.96679)
		(end 28.91028 -221.531688)
		(width 0.20066)
		(layer "F.Cu")
		(net "M_C_CPU1_SB_DQ<10>")
	)
	(segment
		(start 31.972758 -221.541848)
		(end 32.605726 -221.541848)
		(width 0.20066)
		(layer "F.Cu")
		(net "M_C_CPU1_SB_DQ<10>")
	)
	(segment
		(start 32.74949 -221.685612)
		(end 32.74949 -222.01124)
		(width 0.20066)
		(layer "F.Cu")
		(net "M_C_CPU1_SB_DQ<10>")
	)
	(segment
		(start 96.603566 -239.575086)
		(end 96.603566 -239.0394)
		(width 0.20066)
		(layer "F.Cu")
		(net "M_C_CPU1_SB_DQ<10>")
	)
	(segment
		(start 28.91028 -221.531688)
		(end 29.647642 -221.531688)
		(width 0.20066)
		(layer "F.Cu")
		(net "M_C_CPU1_SB_DQ<10>")
	)
	(segment
		(start 52.902866 -225.40722)
		(end 52.902866 -225.608642)
		(width 0.18288)
		(layer "In6.Cu")
		(net "M_C_CPU1_SB_DQ<10>")
	)
	(segment
		(start 93.046296 -239.355122)
		(end 93.031564 -239.363758)
		(width 0.088646)
		(layer "In6.Cu")
		(net "M_C_CPU1_SB_DQ<10>")
	)
	(segment
		(start 60.446666 -227.308664)
		(end 60.263786 -227.491544)
		(width 0.18288)
		(layer "In6.Cu")
		(net "M_C_CPU1_SB_DQ<10>")
	)
	(segment
		(start 73.451974 -237.009432)
		(end 66.486278 -230.043736)
		(width 0.18288)
		(layer "In6.Cu")
		(net "M_C_CPU1_SB_DQ<10>")
	)
	(segment
		(start 86.467696 -239.355122)
		(end 86.452964 -239.363758)
		(width 0.088646)
		(layer "In6.Cu")
		(net "M_C_CPU1_SB_DQ<10>")
	)
	(segment
		(start 60.629546 -226.289362)
		(end 60.446666 -226.472242)
		(width 0.18288)
		(layer "In6.Cu")
		(net "M_C_CPU1_SB_DQ<10>")
	)
	(segment
		(start 87.407496 -239.355122)
		(end 87.392764 -239.363758)
		(width 0.088646)
		(layer "In6.Cu")
		(net "M_C_CPU1_SB_DQ<10>")
	)
	(segment
		(start 38.323266 -221.811342)
		(end 37.998146 -221.811342)
		(width 0.18288)
		(layer "In6.Cu")
		(net "M_C_CPU1_SB_DQ<10>")
	)
	(segment
		(start 53.593746 -225.608642)
		(end 53.593746 -225.40722)
		(width 0.18288)
		(layer "In6.Cu")
		(net "M_C_CPU1_SB_DQ<10>")
	)
	(segment
		(start 60.446666 -226.472242)
		(end 60.446666 -227.308664)
		(width 0.18288)
		(layer "In6.Cu")
		(net "M_C_CPU1_SB_DQ<10>")
	)
	(segment
		(start 59.34456 -227.491544)
		(end 58.691272 -226.838256)
		(width 0.18288)
		(layer "In6.Cu")
		(net "M_C_CPU1_SB_DQ<10>")
	)
	(segment
		(start 64.633602 -228.586792)
		(end 64.28994 -228.24313)
		(width 0.18288)
		(layer "In6.Cu")
		(net "M_C_CPU1_SB_DQ<10>")
	)
	(segment
		(start 83.976464 -238.474504)
		(end 83.336384 -237.834424)
		(width 0.088646)
		(layer "In6.Cu")
		(net "M_C_CPU1_SB_DQ<10>")
	)
	(segment
		(start 83.336384 -237.32236)
		(end 83.023456 -237.009432)
		(width 0.088646)
		(layer "In6.Cu")
		(net "M_C_CPU1_SB_DQ<10>")
	)
	(segment
		(start 57.002934 -225.81743)
		(end 57.002934 -226.655376)
		(width 0.18288)
		(layer "In6.Cu")
		(net "M_C_CPU1_SB_DQ<10>")
	)
	(segment
		(start 40.28059 -222.473266)
		(end 38.689026 -222.473266)
		(width 0.18288)
		(layer "In6.Cu")
		(net "M_C_CPU1_SB_DQ<10>")
	)
	(segment
		(start 85.138768 -239.363758)
		(end 85.129878 -239.358678)
		(width 0.088646)
		(layer "In6.Cu")
		(net "M_C_CPU1_SB_DQ<10>")
	)
	(segment
		(start 57.693814 -226.655376)
		(end 57.693814 -225.796094)
		(width 0.18288)
		(layer "In6.Cu")
		(net "M_C_CPU1_SB_DQ<10>")
	)
	(segment
		(start 40.600884 -222.79356)
		(end 40.28059 -222.473266)
		(width 0.18288)
		(layer "In6.Cu")
		(net "M_C_CPU1_SB_DQ<10>")
	)
	(segment
		(start 41.137332 -223.767904)
		(end 40.600884 -223.231456)
		(width 0.18288)
		(layer "In6.Cu")
		(net "M_C_CPU1_SB_DQ<10>")
	)
	(segment
		(start 93.981778 -239.357662)
		(end 93.971364 -239.363758)
		(width 0.088646)
		(layer "In6.Cu")
		(net "M_C_CPU1_SB_DQ<10>")
	)
	(segment
		(start 47.671228 -224.625408)
		(end 47.355252 -224.941384)
		(width 0.18288)
		(layer "In6.Cu")
		(net "M_C_CPU1_SB_DQ<10>")
	)
	(segment
		(start 48.352964 -224.941384)
		(end 48.036988 -224.625408)
		(width 0.18288)
		(layer "In6.Cu")
		(net "M_C_CPU1_SB_DQ<10>")
	)
	(segment
		(start 53.410866 -225.22434)
		(end 53.085746 -225.22434)
		(width 0.18288)
		(layer "In6.Cu")
		(net "M_C_CPU1_SB_DQ<10>")
	)
	(segment
		(start 45.347128 -224.941384)
		(end 44.173648 -223.767904)
		(width 0.18288)
		(layer "In6.Cu")
		(net "M_C_CPU1_SB_DQ<10>")
	)
	(segment
		(start 37.632386 -222.473266)
		(end 36.48329 -222.473266)
		(width 0.18288)
		(layer "In6.Cu")
		(net "M_C_CPU1_SB_DQ<10>")
	)
	(segment
		(start 89.287096 -239.355122)
		(end 89.272364 -239.363758)
		(width 0.088646)
		(layer "In6.Cu")
		(net "M_C_CPU1_SB_DQ<10>")
	)
	(segment
		(start 61.137546 -227.308664)
		(end 61.137546 -226.472242)
		(width 0.18288)
		(layer "In6.Cu")
		(net "M_C_CPU1_SB_DQ<10>")
	)
	(segment
		(start 92.106496 -239.355122)
		(end 92.091764 -239.363758)
		(width 0.088646)
		(layer "In6.Cu")
		(net "M_C_CPU1_SB_DQ<10>")
	)
	(segment
		(start 49.29505 -224.941384)
		(end 48.352964 -224.941384)
		(width 0.18288)
		(layer "In6.Cu")
		(net "M_C_CPU1_SB_DQ<10>")
	)
	(segment
		(start 56.820054 -226.838256)
		(end 56.069484 -226.838256)
		(width 0.18288)
		(layer "In6.Cu")
		(net "M_C_CPU1_SB_DQ<10>")
	)
	(segment
		(start 61.320426 -227.491544)
		(end 61.137546 -227.308664)
		(width 0.18288)
		(layer "In6.Cu")
		(net "M_C_CPU1_SB_DQ<10>")
	)
	(segment
		(start 52.902866 -225.608642)
		(end 52.719986 -225.791522)
		(width 0.18288)
		(layer "In6.Cu")
		(net "M_C_CPU1_SB_DQ<10>")
	)
	(segment
		(start 95.763588 -238.64316)
		(end 95.407226 -238.688626)
		(width 0.088646)
		(layer "In6.Cu")
		(net "M_C_CPU1_SB_DQ<10>")
	)
	(segment
		(start 94.9198 -239.358678)
		(end 94.91091 -239.363758)
		(width 0.088646)
		(layer "In6.Cu")
		(net "M_C_CPU1_SB_DQ<10>")
	)
	(segment
		(start 60.954666 -226.289362)
		(end 60.629546 -226.289362)
		(width 0.18288)
		(layer "In6.Cu")
		(net "M_C_CPU1_SB_DQ<10>")
	)
	(segment
		(start 53.776626 -225.791522)
		(end 53.593746 -225.608642)
		(width 0.18288)
		(layer "In6.Cu")
		(net "M_C_CPU1_SB_DQ<10>")
	)
	(segment
		(start 37.815266 -221.994222)
		(end 37.815266 -222.290386)
		(width 0.18288)
		(layer "In6.Cu")
		(net "M_C_CPU1_SB_DQ<10>")
	)
	(segment
		(start 53.593746 -225.40722)
		(end 53.410866 -225.22434)
		(width 0.18288)
		(layer "In6.Cu")
		(net "M_C_CPU1_SB_DQ<10>")
	)
	(segment
		(start 88.347296 -239.355122)
		(end 88.332564 -239.363758)
		(width 0.088646)
		(layer "In6.Cu")
		(net "M_C_CPU1_SB_DQ<10>")
	)
	(segment
		(start 38.689026 -222.473266)
		(end 38.506146 -222.290386)
		(width 0.18288)
		(layer "In6.Cu")
		(net "M_C_CPU1_SB_DQ<10>")
	)
	(segment
		(start 57.510934 -225.613214)
		(end 57.20715 -225.613214)
		(width 0.18288)
		(layer "In6.Cu")
		(net "M_C_CPU1_SB_DQ<10>")
	)
	(segment
		(start 38.506146 -221.994222)
		(end 38.323266 -221.811342)
		(width 0.18288)
		(layer "In6.Cu")
		(net "M_C_CPU1_SB_DQ<10>")
	)
	(segment
		(start 55.02275 -225.791522)
		(end 53.776626 -225.791522)
		(width 0.18288)
		(layer "In6.Cu")
		(net "M_C_CPU1_SB_DQ<10>")
	)
	(segment
		(start 62.742826 -227.491544)
		(end 61.320426 -227.491544)
		(width 0.18288)
		(layer "In6.Cu")
		(net "M_C_CPU1_SB_DQ<10>")
	)
	(segment
		(start 57.002934 -226.655376)
		(end 56.820054 -226.838256)
		(width 0.18288)
		(layer "In6.Cu")
		(net "M_C_CPU1_SB_DQ<10>")
	)
	(segment
		(start 84.386166 -238.47425)
		(end 84.385912 -238.474504)
		(width 0.088646)
		(layer "In6.Cu")
		(net "M_C_CPU1_SB_DQ<10>")
	)
	(segment
		(start 60.263786 -227.491544)
		(end 59.34456 -227.491544)
		(width 0.18288)
		(layer "In6.Cu")
		(net "M_C_CPU1_SB_DQ<10>")
	)
	(segment
		(start 64.28994 -228.24313)
		(end 63.494412 -228.24313)
		(width 0.18288)
		(layer "In6.Cu")
		(net "M_C_CPU1_SB_DQ<10>")
	)
	(segment
		(start 63.494412 -228.24313)
		(end 62.742826 -227.491544)
		(width 0.18288)
		(layer "In6.Cu")
		(net "M_C_CPU1_SB_DQ<10>")
	)
	(segment
		(start 66.486278 -230.043736)
		(end 65.540636 -230.043736)
		(width 0.18288)
		(layer "In6.Cu")
		(net "M_C_CPU1_SB_DQ<10>")
	)
	(segment
		(start 85.527896 -239.355122)
		(end 85.513164 -239.363758)
		(width 0.088646)
		(layer "In6.Cu")
		(net "M_C_CPU1_SB_DQ<10>")
	)
	(segment
		(start 84.951316 -239.0394)
		(end 84.951316 -239.029494)
		(width 0.088646)
		(layer "In6.Cu")
		(net "M_C_CPU1_SB_DQ<10>")
	)
	(segment
		(start 40.600884 -223.231456)
		(end 40.600884 -222.79356)
		(width 0.18288)
		(layer "In6.Cu")
		(net "M_C_CPU1_SB_DQ<10>")
	)
	(segment
		(start 37.815266 -222.290386)
		(end 37.632386 -222.473266)
		(width 0.18288)
		(layer "In6.Cu")
		(net "M_C_CPU1_SB_DQ<10>")
	)
	(segment
		(start 36.48329 -222.473266)
		(end 35.976814 -221.96679)
		(width 0.18288)
		(layer "In6.Cu")
		(net "M_C_CPU1_SB_DQ<10>")
	)
	(segment
		(start 38.506146 -222.290386)
		(end 38.506146 -221.994222)
		(width 0.18288)
		(layer "In6.Cu")
		(net "M_C_CPU1_SB_DQ<10>")
	)
	(segment
		(start 37.998146 -221.811342)
		(end 37.815266 -221.994222)
		(width 0.18288)
		(layer "In6.Cu")
		(net "M_C_CPU1_SB_DQ<10>")
	)
	(segment
		(start 53.085746 -225.22434)
		(end 52.902866 -225.40722)
		(width 0.18288)
		(layer "In6.Cu")
		(net "M_C_CPU1_SB_DQ<10>")
	)
	(segment
		(start 82.835496 -237.009432)
		(end 73.451974 -237.009432)
		(width 0.18288)
		(layer "In6.Cu")
		(net "M_C_CPU1_SB_DQ<10>")
	)
	(segment
		(start 57.20715 -225.613214)
		(end 57.002934 -225.81743)
		(width 0.18288)
		(layer "In6.Cu")
		(net "M_C_CPU1_SB_DQ<10>")
	)
	(segment
		(start 91.166696 -239.355122)
		(end 91.151964 -239.363758)
		(width 0.088646)
		(layer "In6.Cu")
		(net "M_C_CPU1_SB_DQ<10>")
	)
	(segment
		(start 48.036988 -224.625408)
		(end 47.671228 -224.625408)
		(width 0.18288)
		(layer "In6.Cu")
		(net "M_C_CPU1_SB_DQ<10>")
	)
	(segment
		(start 57.876694 -226.838256)
		(end 57.693814 -226.655376)
		(width 0.18288)
		(layer "In6.Cu")
		(net "M_C_CPU1_SB_DQ<10>")
	)
	(segment
		(start 44.173648 -223.767904)
		(end 41.137332 -223.767904)
		(width 0.18288)
		(layer "In6.Cu")
		(net "M_C_CPU1_SB_DQ<10>")
	)
	(segment
		(start 56.069484 -226.838256)
		(end 55.02275 -225.791522)
		(width 0.18288)
		(layer "In6.Cu")
		(net "M_C_CPU1_SB_DQ<10>")
	)
	(segment
		(start 57.693814 -225.796094)
		(end 57.510934 -225.613214)
		(width 0.18288)
		(layer "In6.Cu")
		(net "M_C_CPU1_SB_DQ<10>")
	)
	(segment
		(start 50.145188 -225.791522)
		(end 49.29505 -224.941384)
		(width 0.18288)
		(layer "In6.Cu")
		(net "M_C_CPU1_SB_DQ<10>")
	)
	(segment
		(start 58.691272 -226.838256)
		(end 57.876694 -226.838256)
		(width 0.18288)
		(layer "In6.Cu")
		(net "M_C_CPU1_SB_DQ<10>")
	)
	(segment
		(start 52.719986 -225.791522)
		(end 50.145188 -225.791522)
		(width 0.18288)
		(layer "In6.Cu")
		(net "M_C_CPU1_SB_DQ<10>")
	)
	(segment
		(start 64.633602 -229.136702)
		(end 64.633602 -228.586792)
		(width 0.18288)
		(layer "In6.Cu")
		(net "M_C_CPU1_SB_DQ<10>")
	)
	(segment
		(start 83.336384 -237.834424)
		(end 83.336384 -237.32236)
		(width 0.088646)
		(layer "In6.Cu")
		(net "M_C_CPU1_SB_DQ<10>")
	)
	(segment
		(start 61.137546 -226.472242)
		(end 60.954666 -226.289362)
		(width 0.18288)
		(layer "In6.Cu")
		(net "M_C_CPU1_SB_DQ<10>")
	)
	(segment
		(start 83.023456 -237.009432)
		(end 82.835496 -237.009432)
		(width 0.088646)
		(layer "In6.Cu")
		(net "M_C_CPU1_SB_DQ<10>")
	)
	(segment
		(start 65.540636 -230.043736)
		(end 64.633602 -229.136702)
		(width 0.18288)
		(layer "In6.Cu")
		(net "M_C_CPU1_SB_DQ<10>")
	)
	(segment
		(start 84.385912 -238.474504)
		(end 83.976464 -238.474504)
		(width 0.088646)
		(layer "In6.Cu")
		(net "M_C_CPU1_SB_DQ<10>")
	)
	(segment
		(start 47.355252 -224.941384)
		(end 45.347128 -224.941384)
		(width 0.18288)
		(layer "In6.Cu")
		(net "M_C_CPU1_SB_DQ<10>")
	)
	(arc
		(start 93.596968 -239.363758)
		(mid 93.322769 -239.287923)
		(end 93.046296 -239.355122)
		(width 0.088646)
		(layer "In6.Cu")
		(net "M_C_CPU1_SB_DQ<10>")
	)
	(arc
		(start 85.513164 -239.363758)
		(mid 85.325966 -239.413901)
		(end 85.138768 -239.363758)
		(width 0.088646)
		(layer "In6.Cu")
		(net "M_C_CPU1_SB_DQ<10>")
	)
	(arc
		(start 91.151964 -239.363758)
		(mid 90.964766 -239.413901)
		(end 90.777568 -239.363758)
		(width 0.088646)
		(layer "In6.Cu")
		(net "M_C_CPU1_SB_DQ<10>")
	)
	(arc
		(start 92.091764 -239.363758)
		(mid 91.904566 -239.413901)
		(end 91.717368 -239.363758)
		(width 0.088646)
		(layer "In6.Cu")
		(net "M_C_CPU1_SB_DQ<10>")
	)
	(arc
		(start 84.951316 -239.029494)
		(mid 84.782331 -238.63623)
		(end 84.386166 -238.47425)
		(width 0.088646)
		(layer "In6.Cu")
		(net "M_C_CPU1_SB_DQ<10>")
	)
	(arc
		(start 92.657168 -239.363758)
		(mid 92.382969 -239.287923)
		(end 92.106496 -239.355122)
		(width 0.088646)
		(layer "In6.Cu")
		(net "M_C_CPU1_SB_DQ<10>")
	)
	(arc
		(start 88.332564 -239.363758)
		(mid 88.145366 -239.413901)
		(end 87.958168 -239.363758)
		(width 0.088646)
		(layer "In6.Cu")
		(net "M_C_CPU1_SB_DQ<10>")
	)
	(arc
		(start 87.018368 -239.363758)
		(mid 86.744169 -239.287923)
		(end 86.467696 -239.355122)
		(width 0.088646)
		(layer "In6.Cu")
		(net "M_C_CPU1_SB_DQ<10>")
	)
	(arc
		(start 87.958168 -239.363758)
		(mid 87.683969 -239.287923)
		(end 87.407496 -239.355122)
		(width 0.088646)
		(layer "In6.Cu")
		(net "M_C_CPU1_SB_DQ<10>")
	)
	(arc
		(start 86.452964 -239.363758)
		(mid 86.265766 -239.413901)
		(end 86.078568 -239.363758)
		(width 0.088646)
		(layer "In6.Cu")
		(net "M_C_CPU1_SB_DQ<10>")
	)
	(arc
		(start 93.971364 -239.363758)
		(mid 93.784166 -239.413901)
		(end 93.596968 -239.363758)
		(width 0.088646)
		(layer "In6.Cu")
		(net "M_C_CPU1_SB_DQ<10>")
	)
	(arc
		(start 89.837768 -239.363758)
		(mid 89.563569 -239.287923)
		(end 89.287096 -239.355122)
		(width 0.088646)
		(layer "In6.Cu")
		(net "M_C_CPU1_SB_DQ<10>")
	)
	(arc
		(start 91.717368 -239.363758)
		(mid 91.443169 -239.287923)
		(end 91.166696 -239.355122)
		(width 0.088646)
		(layer "In6.Cu")
		(net "M_C_CPU1_SB_DQ<10>")
	)
	(arc
		(start 95.407226 -238.688626)
		(mid 95.186554 -238.805698)
		(end 95.098362 -239.0394)
		(width 0.088646)
		(layer "In6.Cu")
		(net "M_C_CPU1_SB_DQ<10>")
	)
	(arc
		(start 87.392764 -239.363758)
		(mid 87.205566 -239.413901)
		(end 87.018368 -239.363758)
		(width 0.088646)
		(layer "In6.Cu")
		(net "M_C_CPU1_SB_DQ<10>")
	)
	(arc
		(start 90.212164 -239.363758)
		(mid 90.024966 -239.413901)
		(end 89.837768 -239.363758)
		(width 0.088646)
		(layer "In6.Cu")
		(net "M_C_CPU1_SB_DQ<10>")
	)
	(arc
		(start 93.031564 -239.363758)
		(mid 92.844366 -239.413901)
		(end 92.657168 -239.363758)
		(width 0.088646)
		(layer "In6.Cu")
		(net "M_C_CPU1_SB_DQ<10>")
	)
	(arc
		(start 94.91091 -239.363758)
		(mid 94.723712 -239.413901)
		(end 94.536514 -239.363758)
		(width 0.088646)
		(layer "In6.Cu")
		(net "M_C_CPU1_SB_DQ<10>")
	)
	(arc
		(start 88.897968 -239.363758)
		(mid 88.623769 -239.287923)
		(end 88.347296 -239.355122)
		(width 0.088646)
		(layer "In6.Cu")
		(net "M_C_CPU1_SB_DQ<10>")
	)
	(arc
		(start 86.078568 -239.363758)
		(mid 85.804369 -239.287923)
		(end 85.527896 -239.355122)
		(width 0.088646)
		(layer "In6.Cu")
		(net "M_C_CPU1_SB_DQ<10>")
	)
	(arc
		(start 85.129878 -239.358678)
		(mid 84.998964 -239.222318)
		(end 84.951316 -239.0394)
		(width 0.088646)
		(layer "In6.Cu")
		(net "M_C_CPU1_SB_DQ<10>")
	)
	(arc
		(start 96.603566 -239.0394)
		(mid 96.241374 -238.718731)
		(end 95.763588 -238.64316)
		(width 0.088646)
		(layer "In6.Cu")
		(net "M_C_CPU1_SB_DQ<10>")
	)
	(arc
		(start 89.272364 -239.363758)
		(mid 89.085166 -239.413901)
		(end 88.897968 -239.363758)
		(width 0.088646)
		(layer "In6.Cu")
		(net "M_C_CPU1_SB_DQ<10>")
	)
	(arc
		(start 90.777568 -239.363758)
		(mid 90.494866 -239.287982)
		(end 90.212164 -239.363758)
		(width 0.088646)
		(layer "In6.Cu")
		(net "M_C_CPU1_SB_DQ<10>")
	)
	(arc
		(start 94.536514 -239.363758)
		(mid 94.259955 -239.288015)
		(end 93.981778 -239.357662)
		(width 0.088646)
		(layer "In6.Cu")
		(net "M_C_CPU1_SB_DQ<10>")
	)
	(arc
		(start 95.098362 -239.0394)
		(mid 95.050683 -239.2223)
		(end 94.9198 -239.358678)
		(width 0.088646)
		(layer "In6.Cu")
		(net "M_C_CPU1_SB_DQ<10>")
	)
	(segment
		(start 23.228046 -232.166668)
		(end 24.562308 -232.166668)
		(width 0.20066)
		(layer "F.Cu")
		(net "M_C_CPU1_SB_DQ<0>")
	)
	(segment
		(start 24.562308 -232.166668)
		(end 24.801068 -232.405428)
		(width 0.20066)
		(layer "F.Cu")
		(net "M_C_CPU1_SB_DQ<0>")
	)
	(segment
		(start 25.259792 -232.405428)
		(end 25.432512 -232.232708)
		(width 0.20066)
		(layer "F.Cu")
		(net "M_C_CPU1_SB_DQ<0>")
	)
	(segment
		(start 24.801068 -232.405428)
		(end 25.259792 -232.405428)
		(width 0.20066)
		(layer "F.Cu")
		(net "M_C_CPU1_SB_DQ<0>")
	)
	(segment
		(start 25.432512 -231.943148)
		(end 25.642062 -231.733598)
		(width 0.20066)
		(layer "F.Cu")
		(net "M_C_CPU1_SB_DQ<0>")
	)
	(segment
		(start 95.663512 -243.923058)
		(end 95.663766 -243.922804)
		(width 0.20066)
		(layer "F.Cu")
		(net "M_C_CPU1_SB_DQ<0>")
	)
	(segment
		(start 26.20391 -231.733598)
		(end 26.212038 -231.741726)
		(width 0.101854)
		(layer "F.Cu")
		(net "M_C_CPU1_SB_DQ<0>")
	)
	(segment
		(start 29.402786 -232.166668)
		(end 30.771846 -232.166668)
		(width 0.20066)
		(layer "F.Cu")
		(net "M_C_CPU1_SB_DQ<0>")
	)
	(segment
		(start 26.212038 -231.741726)
		(end 26.459942 -231.741726)
		(width 0.101854)
		(layer "F.Cu")
		(net "M_C_CPU1_SB_DQ<0>")
	)
	(segment
		(start 25.432512 -232.232708)
		(end 25.432512 -231.943148)
		(width 0.20066)
		(layer "F.Cu")
		(net "M_C_CPU1_SB_DQ<0>")
	)
	(segment
		(start 25.642062 -231.733598)
		(end 26.20391 -231.733598)
		(width 0.20066)
		(layer "F.Cu")
		(net "M_C_CPU1_SB_DQ<0>")
	)
	(segment
		(start 95.663512 -244.458744)
		(end 95.663512 -243.923058)
		(width 0.20066)
		(layer "F.Cu")
		(net "M_C_CPU1_SB_DQ<0>")
	)
	(segment
		(start 28.529026 -231.741726)
		(end 28.977844 -231.741726)
		(width 0.20066)
		(layer "F.Cu")
		(net "M_C_CPU1_SB_DQ<0>")
	)
	(segment
		(start 31.876746 -232.166668)
		(end 30.771846 -232.166668)
		(width 0.20066)
		(layer "F.Cu")
		(net "M_C_CPU1_SB_DQ<0>")
	)
	(segment
		(start 28.977844 -231.741726)
		(end 29.402786 -232.166668)
		(width 0.20066)
		(layer "F.Cu")
		(net "M_C_CPU1_SB_DQ<0>")
	)
	(segment
		(start 26.459942 -231.741726)
		(end 28.529026 -231.741726)
		(width 0.1016)
		(layer "F.Cu")
		(net "M_C_CPU1_SB_DQ<0>")
	)
	(segment
		(start 63.29299 -239.290352)
		(end 62.54369 -238.541052)
		(width 0.18288)
		(layer "In6.Cu")
		(net "M_C_CPU1_SB_DQ<0>")
	)
	(segment
		(start 58.587132 -238.541052)
		(end 57.642252 -237.596172)
		(width 0.18288)
		(layer "In6.Cu")
		(net "M_C_CPU1_SB_DQ<0>")
	)
	(segment
		(start 91.247214 -244.412262)
		(end 91.2368 -244.418358)
		(width 0.088646)
		(layer "In6.Cu")
		(net "M_C_CPU1_SB_DQ<0>")
	)
	(segment
		(start 51.853846 -238.541814)
		(end 49.968658 -238.541814)
		(width 0.18288)
		(layer "In6.Cu")
		(net "M_C_CPU1_SB_DQ<0>")
	)
	(segment
		(start 94.066614 -244.412262)
		(end 94.051882 -244.420898)
		(width 0.088646)
		(layer "In6.Cu")
		(net "M_C_CPU1_SB_DQ<0>")
	)
	(segment
		(start 31.989014 -232.166668)
		(end 31.876746 -232.166668)
		(width 0.18288)
		(layer "In6.Cu")
		(net "M_C_CPU1_SB_DQ<0>")
	)
	(segment
		(start 65.69202 -240.364772)
		(end 64.6176 -239.290352)
		(width 0.18288)
		(layer "In6.Cu")
		(net "M_C_CPU1_SB_DQ<0>")
	)
	(segment
		(start 88.427814 -244.412262)
		(end 88.413082 -244.420898)
		(width 0.088646)
		(layer "In6.Cu")
		(net "M_C_CPU1_SB_DQ<0>")
	)
	(segment
		(start 92.187268 -244.412262)
		(end 92.176854 -244.418358)
		(width 0.088646)
		(layer "In6.Cu")
		(net "M_C_CPU1_SB_DQ<0>")
	)
	(segment
		(start 49.968658 -238.541814)
		(end 48.268636 -236.841792)
		(width 0.18288)
		(layer "In6.Cu")
		(net "M_C_CPU1_SB_DQ<0>")
	)
	(segment
		(start 40.017446 -235.66247)
		(end 40.017446 -234.282996)
		(width 0.18288)
		(layer "In6.Cu")
		(net "M_C_CPU1_SB_DQ<0>")
	)
	(segment
		(start 40.017446 -234.282996)
		(end 38.103302 -232.368852)
		(width 0.18288)
		(layer "In6.Cu")
		(net "M_C_CPU1_SB_DQ<0>")
	)
	(segment
		(start 84.224368 -244.464586)
		(end 83.089496 -244.464586)
		(width 0.088646)
		(layer "In6.Cu")
		(net "M_C_CPU1_SB_DQ<0>")
	)
	(segment
		(start 90.307668 -244.412262)
		(end 90.297254 -244.418358)
		(width 0.088646)
		(layer "In6.Cu")
		(net "M_C_CPU1_SB_DQ<0>")
	)
	(segment
		(start 41.196768 -236.841792)
		(end 40.017446 -235.66247)
		(width 0.18288)
		(layer "In6.Cu")
		(net "M_C_CPU1_SB_DQ<0>")
	)
	(segment
		(start 70.353936 -243.442236)
		(end 67.276472 -240.364772)
		(width 0.18288)
		(layer "In6.Cu")
		(net "M_C_CPU1_SB_DQ<0>")
	)
	(segment
		(start 62.54369 -238.541052)
		(end 58.587132 -238.541052)
		(width 0.18288)
		(layer "In6.Cu")
		(net "M_C_CPU1_SB_DQ<0>")
	)
	(segment
		(start 36.6776 -232.591864)
		(end 32.41421 -232.591864)
		(width 0.18288)
		(layer "In6.Cu")
		(net "M_C_CPU1_SB_DQ<0>")
	)
	(segment
		(start 67.276472 -240.364772)
		(end 65.69202 -240.364772)
		(width 0.18288)
		(layer "In6.Cu")
		(net "M_C_CPU1_SB_DQ<0>")
	)
	(segment
		(start 83.089496 -244.464586)
		(end 82.45729 -244.464586)
		(width 0.18288)
		(layer "In6.Cu")
		(net "M_C_CPU1_SB_DQ<0>")
	)
	(segment
		(start 95.663766 -243.922804)
		(end 95.62338 -243.882418)
		(width 0.088646)
		(layer "In6.Cu")
		(net "M_C_CPU1_SB_DQ<0>")
	)
	(segment
		(start 89.367614 -244.412262)
		(end 89.352882 -244.420898)
		(width 0.088646)
		(layer "In6.Cu")
		(net "M_C_CPU1_SB_DQ<0>")
	)
	(segment
		(start 36.900612 -232.368852)
		(end 36.6776 -232.591864)
		(width 0.18288)
		(layer "In6.Cu")
		(net "M_C_CPU1_SB_DQ<0>")
	)
	(segment
		(start 38.103302 -232.368852)
		(end 36.900612 -232.368852)
		(width 0.18288)
		(layer "In6.Cu")
		(net "M_C_CPU1_SB_DQ<0>")
	)
	(segment
		(start 93.126814 -244.412262)
		(end 93.1164 -244.418358)
		(width 0.088646)
		(layer "In6.Cu")
		(net "M_C_CPU1_SB_DQ<0>")
	)
	(segment
		(start 95.329502 -243.882418)
		(end 95.289116 -243.922804)
		(width 0.088646)
		(layer "In6.Cu")
		(net "M_C_CPU1_SB_DQ<0>")
	)
	(segment
		(start 32.41421 -232.591864)
		(end 31.989014 -232.166668)
		(width 0.18288)
		(layer "In6.Cu")
		(net "M_C_CPU1_SB_DQ<0>")
	)
	(segment
		(start 95.018606 -244.40515)
		(end 95.006414 -244.412262)
		(width 0.088646)
		(layer "In6.Cu")
		(net "M_C_CPU1_SB_DQ<0>")
	)
	(segment
		(start 57.642252 -237.596172)
		(end 52.799488 -237.596172)
		(width 0.18288)
		(layer "In6.Cu")
		(net "M_C_CPU1_SB_DQ<0>")
	)
	(segment
		(start 81.43494 -243.442236)
		(end 70.353936 -243.442236)
		(width 0.18288)
		(layer "In6.Cu")
		(net "M_C_CPU1_SB_DQ<0>")
	)
	(segment
		(start 52.799488 -237.596172)
		(end 51.853846 -238.541814)
		(width 0.18288)
		(layer "In6.Cu")
		(net "M_C_CPU1_SB_DQ<0>")
	)
	(segment
		(start 48.268636 -236.841792)
		(end 41.196768 -236.841792)
		(width 0.18288)
		(layer "In6.Cu")
		(net "M_C_CPU1_SB_DQ<0>")
	)
	(segment
		(start 82.45729 -244.464586)
		(end 81.43494 -243.442236)
		(width 0.18288)
		(layer "In6.Cu")
		(net "M_C_CPU1_SB_DQ<0>")
	)
	(segment
		(start 95.62338 -243.882418)
		(end 95.329502 -243.882418)
		(width 0.088646)
		(layer "In6.Cu")
		(net "M_C_CPU1_SB_DQ<0>")
	)
	(segment
		(start 64.6176 -239.290352)
		(end 63.29299 -239.290352)
		(width 0.18288)
		(layer "In6.Cu")
		(net "M_C_CPU1_SB_DQ<0>")
	)
	(arc
		(start 86.548214 -244.412262)
		(mid 86.265512 -244.488038)
		(end 85.98281 -244.412262)
		(width 0.088646)
		(layer "In6.Cu")
		(net "M_C_CPU1_SB_DQ<0>")
	)
	(arc
		(start 87.488014 -244.412262)
		(mid 87.205312 -244.488038)
		(end 86.92261 -244.412262)
		(width 0.088646)
		(layer "In6.Cu")
		(net "M_C_CPU1_SB_DQ<0>")
	)
	(arc
		(start 94.051882 -244.420898)
		(mid 93.775407 -244.488218)
		(end 93.50121 -244.412262)
		(width 0.088646)
		(layer "In6.Cu")
		(net "M_C_CPU1_SB_DQ<0>")
	)
	(arc
		(start 90.682064 -244.412262)
		(mid 90.494866 -244.362119)
		(end 90.307668 -244.412262)
		(width 0.088646)
		(layer "In6.Cu")
		(net "M_C_CPU1_SB_DQ<0>")
	)
	(arc
		(start 84.668614 -244.412262)
		(mid 84.451883 -244.484273)
		(end 84.224368 -244.464586)
		(width 0.088646)
		(layer "In6.Cu")
		(net "M_C_CPU1_SB_DQ<0>")
	)
	(arc
		(start 87.86241 -244.412262)
		(mid 87.675212 -244.362119)
		(end 87.488014 -244.412262)
		(width 0.088646)
		(layer "In6.Cu")
		(net "M_C_CPU1_SB_DQ<0>")
	)
	(arc
		(start 93.50121 -244.412262)
		(mid 93.314012 -244.362119)
		(end 93.126814 -244.412262)
		(width 0.088646)
		(layer "In6.Cu")
		(net "M_C_CPU1_SB_DQ<0>")
	)
	(arc
		(start 91.2368 -244.418358)
		(mid 90.958622 -244.488081)
		(end 90.682064 -244.412262)
		(width 0.088646)
		(layer "In6.Cu")
		(net "M_C_CPU1_SB_DQ<0>")
	)
	(arc
		(start 91.62161 -244.412262)
		(mid 91.434412 -244.362119)
		(end 91.247214 -244.412262)
		(width 0.088646)
		(layer "In6.Cu")
		(net "M_C_CPU1_SB_DQ<0>")
	)
	(arc
		(start 88.80221 -244.412262)
		(mid 88.615012 -244.362119)
		(end 88.427814 -244.412262)
		(width 0.088646)
		(layer "In6.Cu")
		(net "M_C_CPU1_SB_DQ<0>")
	)
	(arc
		(start 95.289116 -243.922804)
		(mid 95.216881 -244.199328)
		(end 95.018606 -244.40515)
		(width 0.088646)
		(layer "In6.Cu")
		(net "M_C_CPU1_SB_DQ<0>")
	)
	(arc
		(start 94.44101 -244.412262)
		(mid 94.253812 -244.362119)
		(end 94.066614 -244.412262)
		(width 0.088646)
		(layer "In6.Cu")
		(net "M_C_CPU1_SB_DQ<0>")
	)
	(arc
		(start 85.04301 -244.412262)
		(mid 84.855812 -244.362119)
		(end 84.668614 -244.412262)
		(width 0.088646)
		(layer "In6.Cu")
		(net "M_C_CPU1_SB_DQ<0>")
	)
	(arc
		(start 85.98281 -244.412262)
		(mid 85.795612 -244.362119)
		(end 85.608414 -244.412262)
		(width 0.088646)
		(layer "In6.Cu")
		(net "M_C_CPU1_SB_DQ<0>")
	)
	(arc
		(start 95.006414 -244.412262)
		(mid 94.723712 -244.488038)
		(end 94.44101 -244.412262)
		(width 0.088646)
		(layer "In6.Cu")
		(net "M_C_CPU1_SB_DQ<0>")
	)
	(arc
		(start 92.176854 -244.418358)
		(mid 91.898422 -244.488204)
		(end 91.62161 -244.412262)
		(width 0.088646)
		(layer "In6.Cu")
		(net "M_C_CPU1_SB_DQ<0>")
	)
	(arc
		(start 86.92261 -244.412262)
		(mid 86.735412 -244.362119)
		(end 86.548214 -244.412262)
		(width 0.088646)
		(layer "In6.Cu")
		(net "M_C_CPU1_SB_DQ<0>")
	)
	(arc
		(start 89.352882 -244.420898)
		(mid 89.076407 -244.488218)
		(end 88.80221 -244.412262)
		(width 0.088646)
		(layer "In6.Cu")
		(net "M_C_CPU1_SB_DQ<0>")
	)
	(arc
		(start 90.297254 -244.418358)
		(mid 90.018822 -244.488204)
		(end 89.74201 -244.412262)
		(width 0.088646)
		(layer "In6.Cu")
		(net "M_C_CPU1_SB_DQ<0>")
	)
	(arc
		(start 85.608414 -244.412262)
		(mid 85.325712 -244.488038)
		(end 85.04301 -244.412262)
		(width 0.088646)
		(layer "In6.Cu")
		(net "M_C_CPU1_SB_DQ<0>")
	)
	(arc
		(start 89.74201 -244.412262)
		(mid 89.554812 -244.362119)
		(end 89.367614 -244.412262)
		(width 0.088646)
		(layer "In6.Cu")
		(net "M_C_CPU1_SB_DQ<0>")
	)
	(arc
		(start 88.413082 -244.420898)
		(mid 88.136607 -244.488218)
		(end 87.86241 -244.412262)
		(width 0.088646)
		(layer "In6.Cu")
		(net "M_C_CPU1_SB_DQ<0>")
	)
	(arc
		(start 93.1164 -244.418358)
		(mid 92.838222 -244.488081)
		(end 92.561664 -244.412262)
		(width 0.088646)
		(layer "In6.Cu")
		(net "M_C_CPU1_SB_DQ<0>")
	)
	(arc
		(start 92.561664 -244.412262)
		(mid 92.374466 -244.362119)
		(end 92.187268 -244.412262)
		(width 0.088646)
		(layer "In6.Cu")
		(net "M_C_CPU1_SB_DQ<0>")
	)
	(segment
		(start 34.871914 -244.916706)
		(end 35.976814 -244.916706)
		(width 0.20066)
		(layer "F.Cu")
		(net "M_C_CPU1_SB_CS_N<3>")
	)
	(segment
		(start 93.314266 -243.644928)
		(end 93.314012 -243.644674)
		(width 0.20066)
		(layer "F.Cu")
		(net "M_C_CPU1_SB_CS_N<3>")
	)
	(segment
		(start 93.314012 -243.644674)
		(end 93.314012 -243.108988)
		(width 0.20066)
		(layer "F.Cu")
		(net "M_C_CPU1_SB_CS_N<3>")
	)
	(segment
		(start 52.886356 -244.674644)
		(end 52.703476 -244.491764)
		(width 0.18288)
		(layer "In4.Cu")
		(net "M_C_CPU1_SB_CS_N<3>")
	)
	(segment
		(start 53.760116 -244.491764)
		(end 53.577236 -244.674644)
		(width 0.18288)
		(layer "In4.Cu")
		(net "M_C_CPU1_SB_CS_N<3>")
	)
	(segment
		(start 40.31996 -244.843808)
		(end 39.967916 -244.491764)
		(width 0.18288)
		(layer "In4.Cu")
		(net "M_C_CPU1_SB_CS_N<3>")
	)
	(segment
		(start 62.408562 -244.491764)
		(end 61.602874 -244.491764)
		(width 0.18288)
		(layer "In4.Cu")
		(net "M_C_CPU1_SB_CS_N<3>")
	)
	(segment
		(start 61.602874 -244.491764)
		(end 61.288168 -244.177058)
		(width 0.18288)
		(layer "In4.Cu")
		(net "M_C_CPU1_SB_CS_N<3>")
	)
	(segment
		(start 52.703476 -244.491764)
		(end 49.824894 -244.491764)
		(width 0.18288)
		(layer "In4.Cu")
		(net "M_C_CPU1_SB_CS_N<3>")
	)
	(segment
		(start 64.733424 -244.695726)
		(end 62.612524 -244.695726)
		(width 0.18288)
		(layer "In4.Cu")
		(net "M_C_CPU1_SB_CS_N<3>")
	)
	(segment
		(start 93.314012 -243.108988)
		(end 93.045534 -243.377466)
		(width 0.088646)
		(layer "In4.Cu")
		(net "M_C_CPU1_SB_CS_N<3>")
	)
	(segment
		(start 92.263976 -243.478304)
		(end 92.1766 -243.42725)
		(width 0.088646)
		(layer "In4.Cu")
		(net "M_C_CPU1_SB_CS_N<3>")
	)
	(segment
		(start 49.134014 -244.810788)
		(end 48.81499 -244.491764)
		(width 0.18288)
		(layer "In4.Cu")
		(net "M_C_CPU1_SB_CS_N<3>")
	)
	(segment
		(start 59.906408 -244.177058)
		(end 59.530234 -244.177058)
		(width 0.18288)
		(layer "In4.Cu")
		(net "M_C_CPU1_SB_CS_N<3>")
	)
	(segment
		(start 87.958168 -243.598446)
		(end 87.947754 -243.604542)
		(width 0.088646)
		(layer "In4.Cu")
		(net "M_C_CPU1_SB_CS_N<3>")
	)
	(segment
		(start 83.252564 -245.01983)
		(end 83.06435 -245.01983)
		(width 0.088646)
		(layer "In4.Cu")
		(net "M_C_CPU1_SB_CS_N<3>")
	)
	(segment
		(start 38.339268 -244.843808)
		(end 38.000432 -244.843808)
		(width 0.18288)
		(layer "In4.Cu")
		(net "M_C_CPU1_SB_CS_N<3>")
	)
	(segment
		(start 41.349676 -244.491764)
		(end 41.01084 -244.491764)
		(width 0.18288)
		(layer "In4.Cu")
		(net "M_C_CPU1_SB_CS_N<3>")
	)
	(segment
		(start 60.221114 -244.491764)
		(end 59.906408 -244.177058)
		(width 0.18288)
		(layer "In4.Cu")
		(net "M_C_CPU1_SB_CS_N<3>")
	)
	(segment
		(start 59.530234 -244.177058)
		(end 59.215528 -244.491764)
		(width 0.18288)
		(layer "In4.Cu")
		(net "M_C_CPU1_SB_CS_N<3>")
	)
	(segment
		(start 38.691312 -244.491764)
		(end 38.339268 -244.843808)
		(width 0.18288)
		(layer "In4.Cu")
		(net "M_C_CPU1_SB_CS_N<3>")
	)
	(segment
		(start 65.721484 -244.695726)
		(end 65.459864 -244.434106)
		(width 0.18288)
		(layer "In4.Cu")
		(net "M_C_CPU1_SB_CS_N<3>")
	)
	(segment
		(start 41.01084 -244.491764)
		(end 40.658796 -244.843808)
		(width 0.18288)
		(layer "In4.Cu")
		(net "M_C_CPU1_SB_CS_N<3>")
	)
	(segment
		(start 61.288168 -244.177058)
		(end 60.911994 -244.177058)
		(width 0.18288)
		(layer "In4.Cu")
		(net "M_C_CPU1_SB_CS_N<3>")
	)
	(segment
		(start 48.81499 -244.491764)
		(end 48.443134 -244.491764)
		(width 0.18288)
		(layer "In4.Cu")
		(net "M_C_CPU1_SB_CS_N<3>")
	)
	(segment
		(start 83.535012 -245.302278)
		(end 83.252564 -245.01983)
		(width 0.088646)
		(layer "In4.Cu")
		(net "M_C_CPU1_SB_CS_N<3>")
	)
	(segment
		(start 55.679594 -244.802406)
		(end 55.368952 -244.491764)
		(width 0.18288)
		(layer "In4.Cu")
		(net "M_C_CPU1_SB_CS_N<3>")
	)
	(segment
		(start 52.886356 -244.81917)
		(end 52.886356 -244.674644)
		(width 0.18288)
		(layer "In4.Cu")
		(net "M_C_CPU1_SB_CS_N<3>")
	)
	(segment
		(start 86.078314 -243.598446)
		(end 86.069424 -243.603526)
		(width 0.088646)
		(layer "In4.Cu")
		(net "M_C_CPU1_SB_CS_N<3>")
	)
	(segment
		(start 49.50587 -244.810788)
		(end 49.134014 -244.810788)
		(width 0.18288)
		(layer "In4.Cu")
		(net "M_C_CPU1_SB_CS_N<3>")
	)
	(segment
		(start 59.215528 -244.491764)
		(end 57.752234 -244.491764)
		(width 0.18288)
		(layer "In4.Cu")
		(net "M_C_CPU1_SB_CS_N<3>")
	)
	(segment
		(start 57.061354 -244.802406)
		(end 56.750712 -244.491764)
		(width 0.18288)
		(layer "In4.Cu")
		(net "M_C_CPU1_SB_CS_N<3>")
	)
	(segment
		(start 64.995044 -244.434106)
		(end 64.733424 -244.695726)
		(width 0.18288)
		(layer "In4.Cu")
		(net "M_C_CPU1_SB_CS_N<3>")
	)
	(segment
		(start 88.347296 -243.607082)
		(end 88.332564 -243.598446)
		(width 0.088646)
		(layer "In4.Cu")
		(net "M_C_CPU1_SB_CS_N<3>")
	)
	(segment
		(start 48.12411 -244.810788)
		(end 47.752254 -244.810788)
		(width 0.18288)
		(layer "In4.Cu")
		(net "M_C_CPU1_SB_CS_N<3>")
	)
	(segment
		(start 39.967916 -244.491764)
		(end 38.691312 -244.491764)
		(width 0.18288)
		(layer "In4.Cu")
		(net "M_C_CPU1_SB_CS_N<3>")
	)
	(segment
		(start 62.612524 -244.695726)
		(end 62.408562 -244.491764)
		(width 0.18288)
		(layer "In4.Cu")
		(net "M_C_CPU1_SB_CS_N<3>")
	)
	(segment
		(start 91.247468 -243.433346)
		(end 91.247214 -243.433346)
		(width 0.088646)
		(layer "In4.Cu")
		(net "M_C_CPU1_SB_CS_N<3>")
	)
	(segment
		(start 56.750712 -244.491764)
		(end 56.370474 -244.491764)
		(width 0.18288)
		(layer "In4.Cu")
		(net "M_C_CPU1_SB_CS_N<3>")
	)
	(segment
		(start 47.43323 -244.491764)
		(end 46.306232 -244.491764)
		(width 0.18288)
		(layer "In4.Cu")
		(net "M_C_CPU1_SB_CS_N<3>")
	)
	(segment
		(start 56.370474 -244.491764)
		(end 56.059832 -244.802406)
		(width 0.18288)
		(layer "In4.Cu")
		(net "M_C_CPU1_SB_CS_N<3>")
	)
	(segment
		(start 53.069236 -245.00205)
		(end 52.886356 -244.81917)
		(width 0.18288)
		(layer "In4.Cu")
		(net "M_C_CPU1_SB_CS_N<3>")
	)
	(segment
		(start 85.608414 -244.412262)
		(end 85.599524 -244.417342)
		(width 0.088646)
		(layer "In4.Cu")
		(net "M_C_CPU1_SB_CS_N<3>")
	)
	(segment
		(start 38.000432 -244.843808)
		(end 37.648388 -244.491764)
		(width 0.18288)
		(layer "In4.Cu")
		(net "M_C_CPU1_SB_CS_N<3>")
	)
	(segment
		(start 42.040556 -244.843808)
		(end 41.70172 -244.843808)
		(width 0.18288)
		(layer "In4.Cu")
		(net "M_C_CPU1_SB_CS_N<3>")
	)
	(segment
		(start 57.752234 -244.491764)
		(end 57.441592 -244.802406)
		(width 0.18288)
		(layer "In4.Cu")
		(net "M_C_CPU1_SB_CS_N<3>")
	)
	(segment
		(start 65.459864 -244.434106)
		(end 64.995044 -244.434106)
		(width 0.18288)
		(layer "In4.Cu")
		(net "M_C_CPU1_SB_CS_N<3>")
	)
	(segment
		(start 56.059832 -244.802406)
		(end 55.679594 -244.802406)
		(width 0.18288)
		(layer "In4.Cu")
		(net "M_C_CPU1_SB_CS_N<3>")
	)
	(segment
		(start 47.752254 -244.810788)
		(end 47.43323 -244.491764)
		(width 0.18288)
		(layer "In4.Cu")
		(net "M_C_CPU1_SB_CS_N<3>")
	)
	(segment
		(start 48.443134 -244.491764)
		(end 48.12411 -244.810788)
		(width 0.18288)
		(layer "In4.Cu")
		(net "M_C_CPU1_SB_CS_N<3>")
	)
	(segment
		(start 57.441592 -244.802406)
		(end 57.061354 -244.802406)
		(width 0.18288)
		(layer "In4.Cu")
		(net "M_C_CPU1_SB_CS_N<3>")
	)
	(segment
		(start 36.401756 -244.491764)
		(end 35.976814 -244.916706)
		(width 0.18288)
		(layer "In4.Cu")
		(net "M_C_CPU1_SB_CS_N<3>")
	)
	(segment
		(start 87.018114 -243.598446)
		(end 87.003382 -243.607082)
		(width 0.088646)
		(layer "In4.Cu")
		(net "M_C_CPU1_SB_CS_N<3>")
	)
	(segment
		(start 85.890862 -243.922804)
		(end 85.890862 -243.93271)
		(width 0.088646)
		(layer "In4.Cu")
		(net "M_C_CPU1_SB_CS_N<3>")
	)
	(segment
		(start 46.306232 -244.491764)
		(end 45.961808 -244.836188)
		(width 0.18288)
		(layer "In4.Cu")
		(net "M_C_CPU1_SB_CS_N<3>")
	)
	(segment
		(start 90.212164 -243.598446)
		(end 90.21191 -243.598446)
		(width 0.088646)
		(layer "In4.Cu")
		(net "M_C_CPU1_SB_CS_N<3>")
	)
	(segment
		(start 45.961808 -244.836188)
		(end 45.615352 -244.836188)
		(width 0.18288)
		(layer "In4.Cu")
		(net "M_C_CPU1_SB_CS_N<3>")
	)
	(segment
		(start 42.3926 -244.491764)
		(end 42.040556 -244.843808)
		(width 0.18288)
		(layer "In4.Cu")
		(net "M_C_CPU1_SB_CS_N<3>")
	)
	(segment
		(start 85.420962 -244.73662)
		(end 85.420962 -244.758718)
		(width 0.088646)
		(layer "In4.Cu")
		(net "M_C_CPU1_SB_CS_N<3>")
	)
	(segment
		(start 60.597288 -244.491764)
		(end 60.221114 -244.491764)
		(width 0.18288)
		(layer "In4.Cu")
		(net "M_C_CPU1_SB_CS_N<3>")
	)
	(segment
		(start 67.330574 -245.01983)
		(end 67.00647 -244.695726)
		(width 0.18288)
		(layer "In4.Cu")
		(net "M_C_CPU1_SB_CS_N<3>")
	)
	(segment
		(start 55.368952 -244.491764)
		(end 53.760116 -244.491764)
		(width 0.18288)
		(layer "In4.Cu")
		(net "M_C_CPU1_SB_CS_N<3>")
	)
	(segment
		(start 45.615352 -244.836188)
		(end 45.270928 -244.491764)
		(width 0.18288)
		(layer "In4.Cu")
		(net "M_C_CPU1_SB_CS_N<3>")
	)
	(segment
		(start 53.394356 -245.00205)
		(end 53.069236 -245.00205)
		(width 0.18288)
		(layer "In4.Cu")
		(net "M_C_CPU1_SB_CS_N<3>")
	)
	(segment
		(start 45.270928 -244.491764)
		(end 42.3926 -244.491764)
		(width 0.18288)
		(layer "In4.Cu")
		(net "M_C_CPU1_SB_CS_N<3>")
	)
	(segment
		(start 53.577236 -244.674644)
		(end 53.577236 -244.81917)
		(width 0.18288)
		(layer "In4.Cu")
		(net "M_C_CPU1_SB_CS_N<3>")
	)
	(segment
		(start 60.911994 -244.177058)
		(end 60.597288 -244.491764)
		(width 0.18288)
		(layer "In4.Cu")
		(net "M_C_CPU1_SB_CS_N<3>")
	)
	(segment
		(start 89.272618 -243.598446)
		(end 89.272364 -243.598446)
		(width 0.088646)
		(layer "In4.Cu")
		(net "M_C_CPU1_SB_CS_N<3>")
	)
	(segment
		(start 41.70172 -244.843808)
		(end 41.349676 -244.491764)
		(width 0.18288)
		(layer "In4.Cu")
		(net "M_C_CPU1_SB_CS_N<3>")
	)
	(segment
		(start 37.648388 -244.491764)
		(end 36.401756 -244.491764)
		(width 0.18288)
		(layer "In4.Cu")
		(net "M_C_CPU1_SB_CS_N<3>")
	)
	(segment
		(start 90.68181 -243.433346)
		(end 90.39606 -243.598192)
		(width 0.088646)
		(layer "In4.Cu")
		(net "M_C_CPU1_SB_CS_N<3>")
	)
	(segment
		(start 49.824894 -244.491764)
		(end 49.50587 -244.810788)
		(width 0.18288)
		(layer "In4.Cu")
		(net "M_C_CPU1_SB_CS_N<3>")
	)
	(segment
		(start 67.00647 -244.695726)
		(end 65.721484 -244.695726)
		(width 0.18288)
		(layer "In4.Cu")
		(net "M_C_CPU1_SB_CS_N<3>")
	)
	(segment
		(start 84.588096 -245.234968)
		(end 84.573364 -245.226332)
		(width 0.088646)
		(layer "In4.Cu")
		(net "M_C_CPU1_SB_CS_N<3>")
	)
	(segment
		(start 40.658796 -244.843808)
		(end 40.31996 -244.843808)
		(width 0.18288)
		(layer "In4.Cu")
		(net "M_C_CPU1_SB_CS_N<3>")
	)
	(segment
		(start 83.06435 -245.01983)
		(end 67.330574 -245.01983)
		(width 0.18288)
		(layer "In4.Cu")
		(net "M_C_CPU1_SB_CS_N<3>")
	)
	(segment
		(start 53.577236 -244.81917)
		(end 53.394356 -245.00205)
		(width 0.18288)
		(layer "In4.Cu")
		(net "M_C_CPU1_SB_CS_N<3>")
	)
	(segment
		(start 83.916012 -245.302278)
		(end 83.535012 -245.302278)
		(width 0.088646)
		(layer "In4.Cu")
		(net "M_C_CPU1_SB_CS_N<3>")
	)
	(arc
		(start 87.39251 -243.598446)
		(mid 87.205312 -243.548303)
		(end 87.018114 -243.598446)
		(width 0.088646)
		(layer "In4.Cu")
		(net "M_C_CPU1_SB_CS_N<3>")
	)
	(arc
		(start 86.069424 -243.603526)
		(mid 85.93851 -243.739886)
		(end 85.890862 -243.922804)
		(width 0.088646)
		(layer "In4.Cu")
		(net "M_C_CPU1_SB_CS_N<3>")
	)
	(arc
		(start 85.420962 -244.758718)
		(mid 85.340051 -245.028846)
		(end 85.138768 -245.226332)
		(width 0.088646)
		(layer "In4.Cu")
		(net "M_C_CPU1_SB_CS_N<3>")
	)
	(arc
		(start 85.599524 -244.417342)
		(mid 85.46861 -244.553702)
		(end 85.420962 -244.73662)
		(width 0.088646)
		(layer "In4.Cu")
		(net "M_C_CPU1_SB_CS_N<3>")
	)
	(arc
		(start 89.272364 -243.598446)
		(mid 89.085166 -243.548303)
		(end 88.897968 -243.598446)
		(width 0.088646)
		(layer "In4.Cu")
		(net "M_C_CPU1_SB_CS_N<3>")
	)
	(arc
		(start 88.332564 -243.598446)
		(mid 88.145366 -243.548303)
		(end 87.958168 -243.598446)
		(width 0.088646)
		(layer "In4.Cu")
		(net "M_C_CPU1_SB_CS_N<3>")
	)
	(arc
		(start 92.474288 -243.556028)
		(mid 92.365729 -243.526373)
		(end 92.263976 -243.478304)
		(width 0.088646)
		(layer "In4.Cu")
		(net "M_C_CPU1_SB_CS_N<3>")
	)
	(arc
		(start 91.621864 -243.433346)
		(mid 91.434666 -243.483523)
		(end 91.247468 -243.433346)
		(width 0.088646)
		(layer "In4.Cu")
		(net "M_C_CPU1_SB_CS_N<3>")
	)
	(arc
		(start 88.897968 -243.598446)
		(mid 88.623769 -243.674281)
		(end 88.347296 -243.607082)
		(width 0.088646)
		(layer "In4.Cu")
		(net "M_C_CPU1_SB_CS_N<3>")
	)
	(arc
		(start 93.045534 -243.377466)
		(mid 92.781873 -243.537028)
		(end 92.474288 -243.556028)
		(width 0.088646)
		(layer "In4.Cu")
		(net "M_C_CPU1_SB_CS_N<3>")
	)
	(arc
		(start 87.003382 -243.607082)
		(mid 86.726907 -243.674402)
		(end 86.45271 -243.598446)
		(width 0.088646)
		(layer "In4.Cu")
		(net "M_C_CPU1_SB_CS_N<3>")
	)
	(arc
		(start 91.247214 -243.433346)
		(mid 90.964512 -243.35757)
		(end 90.68181 -243.433346)
		(width 0.088646)
		(layer "In4.Cu")
		(net "M_C_CPU1_SB_CS_N<3>")
	)
	(arc
		(start 90.39606 -243.598192)
		(mid 90.304141 -243.622991)
		(end 90.212164 -243.598446)
		(width 0.088646)
		(layer "In4.Cu")
		(net "M_C_CPU1_SB_CS_N<3>")
	)
	(arc
		(start 84.198968 -245.226332)
		(mid 84.062495 -245.282966)
		(end 83.916012 -245.302278)
		(width 0.088646)
		(layer "In4.Cu")
		(net "M_C_CPU1_SB_CS_N<3>")
	)
	(arc
		(start 85.138768 -245.226332)
		(mid 84.864539 -245.302257)
		(end 84.588096 -245.234968)
		(width 0.088646)
		(layer "In4.Cu")
		(net "M_C_CPU1_SB_CS_N<3>")
	)
	(arc
		(start 84.573364 -245.226332)
		(mid 84.386166 -245.176189)
		(end 84.198968 -245.226332)
		(width 0.088646)
		(layer "In4.Cu")
		(net "M_C_CPU1_SB_CS_N<3>")
	)
	(arc
		(start 92.1766 -243.42725)
		(mid 91.898422 -243.357527)
		(end 91.621864 -243.433346)
		(width 0.088646)
		(layer "In4.Cu")
		(net "M_C_CPU1_SB_CS_N<3>")
	)
	(arc
		(start 89.837768 -243.598446)
		(mid 89.555176 -243.674222)
		(end 89.272618 -243.598446)
		(width 0.088646)
		(layer "In4.Cu")
		(net "M_C_CPU1_SB_CS_N<3>")
	)
	(arc
		(start 87.947754 -243.604542)
		(mid 87.669322 -243.674388)
		(end 87.39251 -243.598446)
		(width 0.088646)
		(layer "In4.Cu")
		(net "M_C_CPU1_SB_CS_N<3>")
	)
	(arc
		(start 85.890862 -243.93271)
		(mid 85.812751 -244.209659)
		(end 85.608414 -244.412262)
		(width 0.088646)
		(layer "In4.Cu")
		(net "M_C_CPU1_SB_CS_N<3>")
	)
	(arc
		(start 86.45271 -243.598446)
		(mid 86.265512 -243.548303)
		(end 86.078314 -243.598446)
		(width 0.088646)
		(layer "In4.Cu")
		(net "M_C_CPU1_SB_CS_N<3>")
	)
	(arc
		(start 90.21191 -243.598446)
		(mid 90.024856 -243.548396)
		(end 89.837768 -243.598446)
		(width 0.088646)
		(layer "In4.Cu")
		(net "M_C_CPU1_SB_CS_N<3>")
	)
	(segment
		(start 93.783912 -244.458744)
		(end 93.784166 -244.45849)
		(width 0.20066)
		(layer "F.Cu")
		(net "M_C_CPU1_SB_CS_N<2>")
	)
	(segment
		(start 93.784166 -244.45849)
		(end 93.784166 -243.922804)
		(width 0.20066)
		(layer "F.Cu")
		(net "M_C_CPU1_SB_CS_N<2>")
	)
	(segment
		(start 30.771846 -245.76659)
		(end 31.876746 -245.76659)
		(width 0.20066)
		(layer "F.Cu")
		(net "M_C_CPU1_SB_CS_N<2>")
	)
	(segment
		(start 38.070028 -245.84152)
		(end 36.662868 -245.84152)
		(width 0.18288)
		(layer "In4.Cu")
		(net "M_C_CPU1_SB_CS_N<2>")
	)
	(segment
		(start 86.078568 -245.226332)
		(end 86.069678 -245.231412)
		(width 0.088646)
		(layer "In4.Cu")
		(net "M_C_CPU1_SB_CS_N<2>")
	)
	(segment
		(start 93.784166 -243.922804)
		(end 93.060774 -244.230144)
		(width 0.088646)
		(layer "In4.Cu")
		(net "M_C_CPU1_SB_CS_N<2>")
	)
	(segment
		(start 36.312602 -246.191786)
		(end 34.97326 -246.191786)
		(width 0.18288)
		(layer "In4.Cu")
		(net "M_C_CPU1_SB_CS_N<2>")
	)
	(segment
		(start 66.668142 -246.01551)
		(end 66.491866 -246.191786)
		(width 0.18288)
		(layer "In4.Cu")
		(net "M_C_CPU1_SB_CS_N<2>")
	)
	(segment
		(start 90.307668 -244.412262)
		(end 90.307414 -244.412262)
		(width 0.088646)
		(layer "In4.Cu")
		(net "M_C_CPU1_SB_CS_N<2>")
	)
	(segment
		(start 36.662868 -245.84152)
		(end 36.312602 -246.191786)
		(width 0.18288)
		(layer "In4.Cu")
		(net "M_C_CPU1_SB_CS_N<2>")
	)
	(segment
		(start 93.060774 -244.230144)
		(end 93.031564 -244.247162)
		(width 0.088646)
		(layer "In4.Cu")
		(net "M_C_CPU1_SB_CS_N<2>")
	)
	(segment
		(start 86.548214 -244.412262)
		(end 86.539324 -244.417342)
		(width 0.088646)
		(layer "In4.Cu")
		(net "M_C_CPU1_SB_CS_N<2>")
	)
	(segment
		(start 86.360762 -244.73662)
		(end 86.360762 -244.758718)
		(width 0.088646)
		(layer "In4.Cu")
		(net "M_C_CPU1_SB_CS_N<2>")
	)
	(segment
		(start 32.472884 -246.362728)
		(end 31.876746 -245.76659)
		(width 0.18288)
		(layer "In4.Cu")
		(net "M_C_CPU1_SB_CS_N<2>")
	)
	(segment
		(start 90.593672 -244.247162)
		(end 90.307668 -244.412262)
		(width 0.088646)
		(layer "In4.Cu")
		(net "M_C_CPU1_SB_CS_N<2>")
	)
	(segment
		(start 84.011516 -246.01551)
		(end 83.06435 -246.01551)
		(width 0.088646)
		(layer "In4.Cu")
		(net "M_C_CPU1_SB_CS_N<2>")
	)
	(segment
		(start 88.427814 -244.412262)
		(end 88.413082 -244.420898)
		(width 0.088646)
		(layer "In4.Cu")
		(net "M_C_CPU1_SB_CS_N<2>")
	)
	(segment
		(start 92.091764 -244.247162)
		(end 92.09151 -244.247162)
		(width 0.088646)
		(layer "In4.Cu")
		(net "M_C_CPU1_SB_CS_N<2>")
	)
	(segment
		(start 34.97326 -246.191786)
		(end 34.802318 -246.362728)
		(width 0.18288)
		(layer "In4.Cu")
		(net "M_C_CPU1_SB_CS_N<2>")
	)
	(segment
		(start 89.367614 -244.412262)
		(end 89.352882 -244.420898)
		(width 0.088646)
		(layer "In4.Cu")
		(net "M_C_CPU1_SB_CS_N<2>")
	)
	(segment
		(start 85.891116 -245.55069)
		(end 85.891116 -245.560596)
		(width 0.088646)
		(layer "In4.Cu")
		(net "M_C_CPU1_SB_CS_N<2>")
	)
	(segment
		(start 83.06435 -246.01551)
		(end 66.668142 -246.01551)
		(width 0.18288)
		(layer "In4.Cu")
		(net "M_C_CPU1_SB_CS_N<2>")
	)
	(segment
		(start 91.152218 -244.247162)
		(end 91.151964 -244.247162)
		(width 0.088646)
		(layer "In4.Cu")
		(net "M_C_CPU1_SB_CS_N<2>")
	)
	(segment
		(start 66.491866 -246.191786)
		(end 38.420294 -246.191786)
		(width 0.18288)
		(layer "In4.Cu")
		(net "M_C_CPU1_SB_CS_N<2>")
	)
	(segment
		(start 38.420294 -246.191786)
		(end 38.070028 -245.84152)
		(width 0.18288)
		(layer "In4.Cu")
		(net "M_C_CPU1_SB_CS_N<2>")
	)
	(segment
		(start 34.802318 -246.362728)
		(end 32.472884 -246.362728)
		(width 0.18288)
		(layer "In4.Cu")
		(net "M_C_CPU1_SB_CS_N<2>")
	)
	(arc
		(start 90.307414 -244.412262)
		(mid 90.024712 -244.488038)
		(end 89.74201 -244.412262)
		(width 0.088646)
		(layer "In4.Cu")
		(net "M_C_CPU1_SB_CS_N<2>")
	)
	(arc
		(start 92.09151 -244.247162)
		(mid 91.904456 -244.297246)
		(end 91.717368 -244.247162)
		(width 0.088646)
		(layer "In4.Cu")
		(net "M_C_CPU1_SB_CS_N<2>")
	)
	(arc
		(start 85.043264 -246.040148)
		(mid 84.856066 -245.990005)
		(end 84.668868 -246.040148)
		(width 0.088646)
		(layer "In4.Cu")
		(net "M_C_CPU1_SB_CS_N<2>")
	)
	(arc
		(start 90.777568 -244.247162)
		(mid 90.68562 -244.222525)
		(end 90.593672 -244.247162)
		(width 0.088646)
		(layer "In4.Cu")
		(net "M_C_CPU1_SB_CS_N<2>")
	)
	(arc
		(start 88.413082 -244.420898)
		(mid 88.136607 -244.488218)
		(end 87.86241 -244.412262)
		(width 0.088646)
		(layer "In4.Cu")
		(net "M_C_CPU1_SB_CS_N<2>")
	)
	(arc
		(start 86.069678 -245.231412)
		(mid 85.938764 -245.367772)
		(end 85.891116 -245.55069)
		(width 0.088646)
		(layer "In4.Cu")
		(net "M_C_CPU1_SB_CS_N<2>")
	)
	(arc
		(start 91.717368 -244.247162)
		(mid 91.434776 -244.171386)
		(end 91.152218 -244.247162)
		(width 0.088646)
		(layer "In4.Cu")
		(net "M_C_CPU1_SB_CS_N<2>")
	)
	(arc
		(start 93.031564 -244.247162)
		(mid 92.844366 -244.297305)
		(end 92.657168 -244.247162)
		(width 0.088646)
		(layer "In4.Cu")
		(net "M_C_CPU1_SB_CS_N<2>")
	)
	(arc
		(start 91.151964 -244.247162)
		(mid 90.964766 -244.297305)
		(end 90.777568 -244.247162)
		(width 0.088646)
		(layer "In4.Cu")
		(net "M_C_CPU1_SB_CS_N<2>")
	)
	(arc
		(start 92.657168 -244.247162)
		(mid 92.374466 -244.17142)
		(end 92.091764 -244.247162)
		(width 0.088646)
		(layer "In4.Cu")
		(net "M_C_CPU1_SB_CS_N<2>")
	)
	(arc
		(start 89.352882 -244.420898)
		(mid 89.076407 -244.488218)
		(end 88.80221 -244.412262)
		(width 0.088646)
		(layer "In4.Cu")
		(net "M_C_CPU1_SB_CS_N<2>")
	)
	(arc
		(start 87.488014 -244.412262)
		(mid 87.205312 -244.488038)
		(end 86.92261 -244.412262)
		(width 0.088646)
		(layer "In4.Cu")
		(net "M_C_CPU1_SB_CS_N<2>")
	)
	(arc
		(start 89.74201 -244.412262)
		(mid 89.554812 -244.362119)
		(end 89.367614 -244.412262)
		(width 0.088646)
		(layer "In4.Cu")
		(net "M_C_CPU1_SB_CS_N<2>")
	)
	(arc
		(start 87.86241 -244.412262)
		(mid 87.675212 -244.362119)
		(end 87.488014 -244.412262)
		(width 0.088646)
		(layer "In4.Cu")
		(net "M_C_CPU1_SB_CS_N<2>")
	)
	(arc
		(start 86.539324 -244.417342)
		(mid 86.40841 -244.553702)
		(end 86.360762 -244.73662)
		(width 0.088646)
		(layer "In4.Cu")
		(net "M_C_CPU1_SB_CS_N<2>")
	)
	(arc
		(start 84.103464 -246.040148)
		(mid 84.059112 -246.021777)
		(end 84.011516 -246.01551)
		(width 0.088646)
		(layer "In4.Cu")
		(net "M_C_CPU1_SB_CS_N<2>")
	)
	(arc
		(start 86.360762 -244.758718)
		(mid 86.279851 -245.028846)
		(end 86.078568 -245.226332)
		(width 0.088646)
		(layer "In4.Cu")
		(net "M_C_CPU1_SB_CS_N<2>")
	)
	(arc
		(start 85.608668 -246.040148)
		(mid 85.325966 -246.115924)
		(end 85.043264 -246.040148)
		(width 0.088646)
		(layer "In4.Cu")
		(net "M_C_CPU1_SB_CS_N<2>")
	)
	(arc
		(start 84.668868 -246.040148)
		(mid 84.386166 -246.115924)
		(end 84.103464 -246.040148)
		(width 0.088646)
		(layer "In4.Cu")
		(net "M_C_CPU1_SB_CS_N<2>")
	)
	(arc
		(start 88.80221 -244.412262)
		(mid 88.615012 -244.362119)
		(end 88.427814 -244.412262)
		(width 0.088646)
		(layer "In4.Cu")
		(net "M_C_CPU1_SB_CS_N<2>")
	)
	(arc
		(start 85.891116 -245.560596)
		(mid 85.813005 -245.837545)
		(end 85.608668 -246.040148)
		(width 0.088646)
		(layer "In4.Cu")
		(net "M_C_CPU1_SB_CS_N<2>")
	)
	(arc
		(start 86.92261 -244.412262)
		(mid 86.735412 -244.362119)
		(end 86.548214 -244.412262)
		(width 0.088646)
		(layer "In4.Cu")
		(net "M_C_CPU1_SB_CS_N<2>")
	)
	(segment
		(start 92.374466 -243.644928)
		(end 92.374212 -243.644674)
		(width 0.20066)
		(layer "F.Cu")
		(net "M_C_CPU1_SB_CS_N<1>")
	)
	(segment
		(start 27.328114 -244.916706)
		(end 28.433014 -244.916706)
		(width 0.20066)
		(layer "F.Cu")
		(net "M_C_CPU1_SB_CS_N<1>")
	)
	(segment
		(start 92.374212 -243.644674)
		(end 92.374212 -243.108988)
		(width 0.20066)
		(layer "F.Cu")
		(net "M_C_CPU1_SB_CS_N<1>")
	)
	(segment
		(start 35.062414 -243.824506)
		(end 35.062414 -244.653054)
		(width 0.18288)
		(layer "In4.Cu")
		(net "M_C_CPU1_SB_CS_N<1>")
	)
	(segment
		(start 56.996076 -243.640864)
		(end 56.995314 -243.641626)
		(width 0.18288)
		(layer "In4.Cu")
		(net "M_C_CPU1_SB_CS_N<1>")
	)
	(segment
		(start 36.839398 -243.220494)
		(end 36.839398 -243.458746)
		(width 0.18288)
		(layer "In4.Cu")
		(net "M_C_CPU1_SB_CS_N<1>")
	)
	(segment
		(start 30.11297 -243.641626)
		(end 29.708094 -243.641626)
		(width 0.18288)
		(layer "In4.Cu")
		(net "M_C_CPU1_SB_CS_N<1>")
	)
	(segment
		(start 85.983064 -243.433346)
		(end 85.976968 -243.436902)
		(width 0.088646)
		(layer "In4.Cu")
		(net "M_C_CPU1_SB_CS_N<1>")
	)
	(segment
		(start 30.29585 -243.824506)
		(end 30.11297 -243.641626)
		(width 0.18288)
		(layer "In4.Cu")
		(net "M_C_CPU1_SB_CS_N<1>")
	)
	(segment
		(start 42.72026 -243.340382)
		(end 41.110154 -243.340382)
		(width 0.18288)
		(layer "In4.Cu")
		(net "M_C_CPU1_SB_CS_N<1>")
	)
	(segment
		(start 53.183028 -243.64061)
		(end 52.857146 -243.64061)
		(width 0.18288)
		(layer "In4.Cu")
		(net "M_C_CPU1_SB_CS_N<1>")
	)
	(segment
		(start 92.374212 -243.108988)
		(end 91.669616 -242.70208)
		(width 0.088646)
		(layer "In4.Cu")
		(net "M_C_CPU1_SB_CS_N<1>")
	)
	(segment
		(start 51.912774 -243.43106)
		(end 51.702208 -243.641626)
		(width 0.18288)
		(layer "In4.Cu")
		(net "M_C_CPU1_SB_CS_N<1>")
	)
	(segment
		(start 52.647596 -243.43106)
		(end 51.912774 -243.43106)
		(width 0.18288)
		(layer "In4.Cu")
		(net "M_C_CPU1_SB_CS_N<1>")
	)
	(segment
		(start 58.326274 -243.640864)
		(end 56.996076 -243.640864)
		(width 0.18288)
		(layer "In4.Cu")
		(net "M_C_CPU1_SB_CS_N<1>")
	)
	(segment
		(start 29.708094 -243.641626)
		(end 28.433014 -244.916706)
		(width 0.18288)
		(layer "In4.Cu")
		(net "M_C_CPU1_SB_CS_N<1>")
	)
	(segment
		(start 85.997796 -243.42471)
		(end 85.983064 -243.433346)
		(width 0.088646)
		(layer "In4.Cu")
		(net "M_C_CPU1_SB_CS_N<1>")
	)
	(segment
		(start 61.427868 -243.518436)
		(end 58.448702 -243.518436)
		(width 0.18288)
		(layer "In4.Cu")
		(net "M_C_CPU1_SB_CS_N<1>")
	)
	(segment
		(start 35.062414 -244.653054)
		(end 34.879534 -244.835934)
		(width 0.18288)
		(layer "In4.Cu")
		(net "M_C_CPU1_SB_CS_N<1>")
	)
	(segment
		(start 30.98673 -243.824506)
		(end 30.98673 -244.611144)
		(width 0.18288)
		(layer "In4.Cu")
		(net "M_C_CPU1_SB_CS_N<1>")
	)
	(segment
		(start 34.371534 -243.824506)
		(end 34.188654 -243.641626)
		(width 0.18288)
		(layer "In4.Cu")
		(net "M_C_CPU1_SB_CS_N<1>")
	)
	(segment
		(start 52.857146 -243.64061)
		(end 52.647596 -243.43106)
		(width 0.18288)
		(layer "In4.Cu")
		(net "M_C_CPU1_SB_CS_N<1>")
	)
	(segment
		(start 90.307414 -242.78463)
		(end 90.021664 -242.94973)
		(width 0.088646)
		(layer "In4.Cu")
		(net "M_C_CPU1_SB_CS_N<1>")
	)
	(segment
		(start 43.021504 -243.641626)
		(end 42.72026 -243.340382)
		(width 0.18288)
		(layer "In4.Cu")
		(net "M_C_CPU1_SB_CS_N<1>")
	)
	(segment
		(start 65.88506 -243.430298)
		(end 65.673732 -243.641626)
		(width 0.18288)
		(layer "In4.Cu")
		(net "M_C_CPU1_SB_CS_N<1>")
	)
	(segment
		(start 89.367614 -243.433346)
		(end 89.352882 -243.42471)
		(width 0.088646)
		(layer "In4.Cu")
		(net "M_C_CPU1_SB_CS_N<1>")
	)
	(segment
		(start 89.367868 -243.433346)
		(end 89.367614 -243.433346)
		(width 0.088646)
		(layer "In4.Cu")
		(net "M_C_CPU1_SB_CS_N<1>")
	)
	(segment
		(start 37.530278 -243.220494)
		(end 37.347398 -243.037614)
		(width 0.18288)
		(layer "In4.Cu")
		(net "M_C_CPU1_SB_CS_N<1>")
	)
	(segment
		(start 34.188654 -243.641626)
		(end 31.16961 -243.641626)
		(width 0.18288)
		(layer "In4.Cu")
		(net "M_C_CPU1_SB_CS_N<1>")
	)
	(segment
		(start 34.554414 -244.835934)
		(end 34.371534 -244.653054)
		(width 0.18288)
		(layer "In4.Cu")
		(net "M_C_CPU1_SB_CS_N<1>")
	)
	(segment
		(start 68.782692 -244.52199)
		(end 67.691 -243.430298)
		(width 0.18288)
		(layer "In4.Cu")
		(net "M_C_CPU1_SB_CS_N<1>")
	)
	(segment
		(start 83.06435 -244.52199)
		(end 68.782692 -244.52199)
		(width 0.18288)
		(layer "In4.Cu")
		(net "M_C_CPU1_SB_CS_N<1>")
	)
	(segment
		(start 35.245294 -243.641626)
		(end 35.062414 -243.824506)
		(width 0.18288)
		(layer "In4.Cu")
		(net "M_C_CPU1_SB_CS_N<1>")
	)
	(segment
		(start 83.826096 -245.112032)
		(end 83.236054 -244.52199)
		(width 0.088646)
		(layer "In4.Cu")
		(net "M_C_CPU1_SB_CS_N<1>")
	)
	(segment
		(start 91.199716 -242.70208)
		(end 91.05646 -242.78463)
		(width 0.088646)
		(layer "In4.Cu")
		(net "M_C_CPU1_SB_CS_N<1>")
	)
	(segment
		(start 37.022278 -243.037614)
		(end 36.839398 -243.220494)
		(width 0.18288)
		(layer "In4.Cu")
		(net "M_C_CPU1_SB_CS_N<1>")
	)
	(segment
		(start 37.530278 -243.458746)
		(end 37.530278 -243.220494)
		(width 0.18288)
		(layer "In4.Cu")
		(net "M_C_CPU1_SB_CS_N<1>")
	)
	(segment
		(start 88.427814 -243.433346)
		(end 88.4174 -243.42725)
		(width 0.088646)
		(layer "In4.Cu")
		(net "M_C_CPU1_SB_CS_N<1>")
	)
	(segment
		(start 85.5218 -244.242082)
		(end 85.51291 -244.247162)
		(width 0.088646)
		(layer "In4.Cu")
		(net "M_C_CPU1_SB_CS_N<1>")
	)
	(segment
		(start 83.236054 -244.52199)
		(end 83.06435 -244.52199)
		(width 0.088646)
		(layer "In4.Cu")
		(net "M_C_CPU1_SB_CS_N<1>")
	)
	(segment
		(start 67.691 -243.430298)
		(end 65.88506 -243.430298)
		(width 0.18288)
		(layer "In4.Cu")
		(net "M_C_CPU1_SB_CS_N<1>")
	)
	(segment
		(start 65.673732 -243.641626)
		(end 61.551058 -243.641626)
		(width 0.18288)
		(layer "In4.Cu")
		(net "M_C_CPU1_SB_CS_N<1>")
	)
	(segment
		(start 36.839398 -243.458746)
		(end 36.656518 -243.641626)
		(width 0.18288)
		(layer "In4.Cu")
		(net "M_C_CPU1_SB_CS_N<1>")
	)
	(segment
		(start 30.47873 -244.794024)
		(end 30.29585 -244.611144)
		(width 0.18288)
		(layer "In4.Cu")
		(net "M_C_CPU1_SB_CS_N<1>")
	)
	(segment
		(start 37.347398 -243.037614)
		(end 37.022278 -243.037614)
		(width 0.18288)
		(layer "In4.Cu")
		(net "M_C_CPU1_SB_CS_N<1>")
	)
	(segment
		(start 37.713158 -243.641626)
		(end 37.530278 -243.458746)
		(width 0.18288)
		(layer "In4.Cu")
		(net "M_C_CPU1_SB_CS_N<1>")
	)
	(segment
		(start 30.29585 -244.611144)
		(end 30.29585 -243.824506)
		(width 0.18288)
		(layer "In4.Cu")
		(net "M_C_CPU1_SB_CS_N<1>")
	)
	(segment
		(start 84.668614 -245.060978)
		(end 84.653882 -245.052342)
		(width 0.088646)
		(layer "In4.Cu")
		(net "M_C_CPU1_SB_CS_N<1>")
	)
	(segment
		(start 58.448702 -243.518436)
		(end 58.326274 -243.640864)
		(width 0.18288)
		(layer "In4.Cu")
		(net "M_C_CPU1_SB_CS_N<1>")
	)
	(segment
		(start 34.879534 -244.835934)
		(end 34.554414 -244.835934)
		(width 0.18288)
		(layer "In4.Cu")
		(net "M_C_CPU1_SB_CS_N<1>")
	)
	(segment
		(start 36.656518 -243.641626)
		(end 35.245294 -243.641626)
		(width 0.18288)
		(layer "In4.Cu")
		(net "M_C_CPU1_SB_CS_N<1>")
	)
	(segment
		(start 89.742264 -243.433092)
		(end 89.74201 -243.433346)
		(width 0.088646)
		(layer "In4.Cu")
		(net "M_C_CPU1_SB_CS_N<1>")
	)
	(segment
		(start 41.110154 -243.340382)
		(end 40.80891 -243.641626)
		(width 0.18288)
		(layer "In4.Cu")
		(net "M_C_CPU1_SB_CS_N<1>")
	)
	(segment
		(start 34.371534 -244.653054)
		(end 34.371534 -243.824506)
		(width 0.18288)
		(layer "In4.Cu")
		(net "M_C_CPU1_SB_CS_N<1>")
	)
	(segment
		(start 40.80891 -243.641626)
		(end 37.713158 -243.641626)
		(width 0.18288)
		(layer "In4.Cu")
		(net "M_C_CPU1_SB_CS_N<1>")
	)
	(segment
		(start 31.16961 -243.641626)
		(end 30.98673 -243.824506)
		(width 0.18288)
		(layer "In4.Cu")
		(net "M_C_CPU1_SB_CS_N<1>")
	)
	(segment
		(start 30.98673 -244.611144)
		(end 30.80385 -244.794024)
		(width 0.18288)
		(layer "In4.Cu")
		(net "M_C_CPU1_SB_CS_N<1>")
	)
	(segment
		(start 53.184044 -243.641626)
		(end 53.183028 -243.64061)
		(width 0.18288)
		(layer "In4.Cu")
		(net "M_C_CPU1_SB_CS_N<1>")
	)
	(segment
		(start 85.230462 -244.726714)
		(end 85.230462 -244.73662)
		(width 0.088646)
		(layer "In4.Cu")
		(net "M_C_CPU1_SB_CS_N<1>")
	)
	(segment
		(start 83.916012 -245.112032)
		(end 83.826096 -245.112032)
		(width 0.088646)
		(layer "In4.Cu")
		(net "M_C_CPU1_SB_CS_N<1>")
	)
	(segment
		(start 56.995314 -243.641626)
		(end 53.184044 -243.641626)
		(width 0.18288)
		(layer "In4.Cu")
		(net "M_C_CPU1_SB_CS_N<1>")
	)
	(segment
		(start 61.551058 -243.641626)
		(end 61.427868 -243.518436)
		(width 0.18288)
		(layer "In4.Cu")
		(net "M_C_CPU1_SB_CS_N<1>")
	)
	(segment
		(start 85.0519 -245.055898)
		(end 85.04301 -245.060978)
		(width 0.088646)
		(layer "In4.Cu")
		(net "M_C_CPU1_SB_CS_N<1>")
	)
	(segment
		(start 86.937596 -243.42471)
		(end 86.922864 -243.433346)
		(width 0.088646)
		(layer "In4.Cu")
		(net "M_C_CPU1_SB_CS_N<1>")
	)
	(segment
		(start 51.702208 -243.641626)
		(end 43.021504 -243.641626)
		(width 0.18288)
		(layer "In4.Cu")
		(net "M_C_CPU1_SB_CS_N<1>")
	)
	(segment
		(start 30.80385 -244.794024)
		(end 30.47873 -244.794024)
		(width 0.18288)
		(layer "In4.Cu")
		(net "M_C_CPU1_SB_CS_N<1>")
	)
	(arc
		(start 89.74201 -243.433346)
		(mid 89.554956 -243.483396)
		(end 89.367868 -243.433346)
		(width 0.088646)
		(layer "In4.Cu")
		(net "M_C_CPU1_SB_CS_N<1>")
	)
	(arc
		(start 85.51291 -244.247162)
		(mid 85.308575 -244.449767)
		(end 85.230462 -244.726714)
		(width 0.088646)
		(layer "In4.Cu")
		(net "M_C_CPU1_SB_CS_N<1>")
	)
	(arc
		(start 90.68181 -242.78463)
		(mid 90.494612 -242.734487)
		(end 90.307414 -242.78463)
		(width 0.088646)
		(layer "In4.Cu")
		(net "M_C_CPU1_SB_CS_N<1>")
	)
	(arc
		(start 85.976968 -243.436902)
		(mid 85.774381 -243.643253)
		(end 85.700362 -243.922804)
		(width 0.088646)
		(layer "In4.Cu")
		(net "M_C_CPU1_SB_CS_N<1>")
	)
	(arc
		(start 86.548468 -243.433346)
		(mid 86.274269 -243.357511)
		(end 85.997796 -243.42471)
		(width 0.088646)
		(layer "In4.Cu")
		(net "M_C_CPU1_SB_CS_N<1>")
	)
	(arc
		(start 84.653882 -245.052342)
		(mid 84.377441 -244.985176)
		(end 84.10321 -245.060978)
		(width 0.088646)
		(layer "In4.Cu")
		(net "M_C_CPU1_SB_CS_N<1>")
	)
	(arc
		(start 91.05646 -242.78463)
		(mid 90.869118 -242.8349)
		(end 90.68181 -242.78463)
		(width 0.088646)
		(layer "In4.Cu")
		(net "M_C_CPU1_SB_CS_N<1>")
	)
	(arc
		(start 85.230462 -244.73662)
		(mid 85.182783 -244.91952)
		(end 85.0519 -245.055898)
		(width 0.088646)
		(layer "In4.Cu")
		(net "M_C_CPU1_SB_CS_N<1>")
	)
	(arc
		(start 90.021664 -242.94973)
		(mid 89.954175 -243.016977)
		(end 89.929462 -243.108988)
		(width 0.088646)
		(layer "In4.Cu")
		(net "M_C_CPU1_SB_CS_N<1>")
	)
	(arc
		(start 89.352882 -243.42471)
		(mid 89.076407 -243.35739)
		(end 88.80221 -243.433346)
		(width 0.088646)
		(layer "In4.Cu")
		(net "M_C_CPU1_SB_CS_N<1>")
	)
	(arc
		(start 86.922864 -243.433346)
		(mid 86.735666 -243.483489)
		(end 86.548468 -243.433346)
		(width 0.088646)
		(layer "In4.Cu")
		(net "M_C_CPU1_SB_CS_N<1>")
	)
	(arc
		(start 85.700362 -243.922804)
		(mid 85.652683 -244.105704)
		(end 85.5218 -244.242082)
		(width 0.088646)
		(layer "In4.Cu")
		(net "M_C_CPU1_SB_CS_N<1>")
	)
	(arc
		(start 88.4174 -243.42725)
		(mid 88.139222 -243.357527)
		(end 87.862664 -243.433346)
		(width 0.088646)
		(layer "In4.Cu")
		(net "M_C_CPU1_SB_CS_N<1>")
	)
	(arc
		(start 89.929462 -243.108988)
		(mid 89.879298 -243.296126)
		(end 89.742264 -243.433092)
		(width 0.088646)
		(layer "In4.Cu")
		(net "M_C_CPU1_SB_CS_N<1>")
	)
	(arc
		(start 87.488268 -243.433346)
		(mid 87.214069 -243.357511)
		(end 86.937596 -243.42471)
		(width 0.088646)
		(layer "In4.Cu")
		(net "M_C_CPU1_SB_CS_N<1>")
	)
	(arc
		(start 84.10321 -245.060978)
		(mid 84.012974 -245.098848)
		(end 83.916012 -245.112032)
		(width 0.088646)
		(layer "In4.Cu")
		(net "M_C_CPU1_SB_CS_N<1>")
	)
	(arc
		(start 91.669616 -242.70208)
		(mid 91.434666 -242.63912)
		(end 91.199716 -242.70208)
		(width 0.088646)
		(layer "In4.Cu")
		(net "M_C_CPU1_SB_CS_N<1>")
	)
	(arc
		(start 87.862664 -243.433346)
		(mid 87.675466 -243.483489)
		(end 87.488268 -243.433346)
		(width 0.088646)
		(layer "In4.Cu")
		(net "M_C_CPU1_SB_CS_N<1>")
	)
	(arc
		(start 85.04301 -245.060978)
		(mid 84.855812 -245.111121)
		(end 84.668614 -245.060978)
		(width 0.088646)
		(layer "In4.Cu")
		(net "M_C_CPU1_SB_CS_N<1>")
	)
	(arc
		(start 88.80221 -243.433346)
		(mid 88.615012 -243.483489)
		(end 88.427814 -243.433346)
		(width 0.088646)
		(layer "In4.Cu")
		(net "M_C_CPU1_SB_CS_N<1>")
	)
	(segment
		(start 91.904312 -244.458744)
		(end 91.904566 -244.45849)
		(width 0.20066)
		(layer "F.Cu")
		(net "M_C_CPU1_SB_CS_N<0>")
	)
	(segment
		(start 23.228046 -245.76659)
		(end 24.332946 -245.76659)
		(width 0.20066)
		(layer "F.Cu")
		(net "M_C_CPU1_SB_CS_N<0>")
	)
	(segment
		(start 91.904566 -244.45849)
		(end 91.904566 -243.922804)
		(width 0.20066)
		(layer "F.Cu")
		(net "M_C_CPU1_SB_CS_N<0>")
	)
	(segment
		(start 55.322978 -245.518686)
		(end 52.003198 -245.518686)
		(width 0.18288)
		(layer "In4.Cu")
		(net "M_C_CPU1_SB_CS_N<0>")
	)
	(segment
		(start 90.212164 -244.247162)
		(end 90.21191 -244.247162)
		(width 0.088646)
		(layer "In4.Cu")
		(net "M_C_CPU1_SB_CS_N<0>")
	)
	(segment
		(start 64.618108 -245.270274)
		(end 62.94374 -245.270274)
		(width 0.18288)
		(layer "In4.Cu")
		(net "M_C_CPU1_SB_CS_N<0>")
	)
	(segment
		(start 91.179904 -243.614702)
		(end 91.151964 -243.598446)
		(width 0.088646)
		(layer "In4.Cu")
		(net "M_C_CPU1_SB_CS_N<0>")
	)
	(segment
		(start 91.904566 -243.922804)
		(end 91.179904 -243.614702)
		(width 0.088646)
		(layer "In4.Cu")
		(net "M_C_CPU1_SB_CS_N<0>")
	)
	(segment
		(start 29.057346 -245.93042)
		(end 29.057346 -245.524528)
		(width 0.18288)
		(layer "In4.Cu")
		(net "M_C_CPU1_SB_CS_N<0>")
	)
	(segment
		(start 24.757888 -245.341648)
		(end 24.332946 -245.76659)
		(width 0.18288)
		(layer "In4.Cu")
		(net "M_C_CPU1_SB_CS_N<0>")
	)
	(segment
		(start 62.799722 -245.414292)
		(end 59.138312 -245.414292)
		(width 0.18288)
		(layer "In4.Cu")
		(net "M_C_CPU1_SB_CS_N<0>")
	)
	(segment
		(start 83.294982 -245.51767)
		(end 83.06435 -245.51767)
		(width 0.088646)
		(layer "In4.Cu")
		(net "M_C_CPU1_SB_CS_N<0>")
	)
	(segment
		(start 89.287096 -244.238526)
		(end 89.272364 -244.247162)
		(width 0.088646)
		(layer "In4.Cu")
		(net "M_C_CPU1_SB_CS_N<0>")
	)
	(segment
		(start 55.524908 -245.316756)
		(end 55.322978 -245.518686)
		(width 0.18288)
		(layer "In4.Cu")
		(net "M_C_CPU1_SB_CS_N<0>")
	)
	(segment
		(start 29.565346 -246.1133)
		(end 29.240226 -246.1133)
		(width 0.18288)
		(layer "In4.Cu")
		(net "M_C_CPU1_SB_CS_N<0>")
	)
	(segment
		(start 85.9917 -245.055898)
		(end 85.98281 -245.060978)
		(width 0.088646)
		(layer "In4.Cu")
		(net "M_C_CPU1_SB_CS_N<0>")
	)
	(segment
		(start 30.439106 -245.93042)
		(end 30.439106 -245.524528)
		(width 0.18288)
		(layer "In4.Cu")
		(net "M_C_CPU1_SB_CS_N<0>")
	)
	(segment
		(start 58.45937 -245.161816)
		(end 58.30443 -245.316756)
		(width 0.18288)
		(layer "In4.Cu")
		(net "M_C_CPU1_SB_CS_N<0>")
	)
	(segment
		(start 90.212418 -244.246908)
		(end 90.212164 -244.247162)
		(width 0.088646)
		(layer "In4.Cu")
		(net "M_C_CPU1_SB_CS_N<0>")
	)
	(segment
		(start 88.347296 -244.238526)
		(end 88.332564 -244.247162)
		(width 0.088646)
		(layer "In4.Cu")
		(net "M_C_CPU1_SB_CS_N<0>")
	)
	(segment
		(start 31.129986 -245.524528)
		(end 31.129986 -245.93042)
		(width 0.18288)
		(layer "In4.Cu")
		(net "M_C_CPU1_SB_CS_N<0>")
	)
	(segment
		(start 62.94374 -245.270274)
		(end 62.799722 -245.414292)
		(width 0.18288)
		(layer "In4.Cu")
		(net "M_C_CPU1_SB_CS_N<0>")
	)
	(segment
		(start 30.256226 -245.341648)
		(end 29.931106 -245.341648)
		(width 0.18288)
		(layer "In4.Cu")
		(net "M_C_CPU1_SB_CS_N<0>")
	)
	(segment
		(start 65.606168 -245.270274)
		(end 65.311782 -245.56466)
		(width 0.18288)
		(layer "In4.Cu")
		(net "M_C_CPU1_SB_CS_N<0>")
	)
	(segment
		(start 29.240226 -246.1133)
		(end 29.057346 -245.93042)
		(width 0.18288)
		(layer "In4.Cu")
		(net "M_C_CPU1_SB_CS_N<0>")
	)
	(segment
		(start 85.700616 -245.528592)
		(end 85.700616 -245.55069)
		(width 0.088646)
		(layer "In4.Cu")
		(net "M_C_CPU1_SB_CS_N<0>")
	)
	(segment
		(start 90.777568 -243.598446)
		(end 90.491564 -243.7638)
		(width 0.088646)
		(layer "In4.Cu")
		(net "M_C_CPU1_SB_CS_N<0>")
	)
	(segment
		(start 30.621986 -246.1133)
		(end 30.439106 -245.93042)
		(width 0.18288)
		(layer "In4.Cu")
		(net "M_C_CPU1_SB_CS_N<0>")
	)
	(segment
		(start 83.576668 -245.799356)
		(end 83.294982 -245.51767)
		(width 0.088646)
		(layer "In4.Cu")
		(net "M_C_CPU1_SB_CS_N<0>")
	)
	(segment
		(start 30.439106 -245.524528)
		(end 30.256226 -245.341648)
		(width 0.18288)
		(layer "In4.Cu")
		(net "M_C_CPU1_SB_CS_N<0>")
	)
	(segment
		(start 85.522054 -245.869968)
		(end 85.513164 -245.875048)
		(width 0.088646)
		(layer "In4.Cu")
		(net "M_C_CPU1_SB_CS_N<0>")
	)
	(segment
		(start 64.912494 -245.56466)
		(end 64.618108 -245.270274)
		(width 0.18288)
		(layer "In4.Cu")
		(net "M_C_CPU1_SB_CS_N<0>")
	)
	(segment
		(start 87.402924 -244.241066)
		(end 87.39251 -244.247162)
		(width 0.088646)
		(layer "In4.Cu")
		(net "M_C_CPU1_SB_CS_N<0>")
	)
	(segment
		(start 29.057346 -245.524528)
		(end 28.874466 -245.341648)
		(width 0.18288)
		(layer "In4.Cu")
		(net "M_C_CPU1_SB_CS_N<0>")
	)
	(segment
		(start 66.921126 -245.51767)
		(end 66.67373 -245.270274)
		(width 0.18288)
		(layer "In4.Cu")
		(net "M_C_CPU1_SB_CS_N<0>")
	)
	(segment
		(start 28.874466 -245.341648)
		(end 24.757888 -245.341648)
		(width 0.18288)
		(layer "In4.Cu")
		(net "M_C_CPU1_SB_CS_N<0>")
	)
	(segment
		(start 58.30443 -245.316756)
		(end 55.524908 -245.316756)
		(width 0.18288)
		(layer "In4.Cu")
		(net "M_C_CPU1_SB_CS_N<0>")
	)
	(segment
		(start 65.311782 -245.56466)
		(end 64.912494 -245.56466)
		(width 0.18288)
		(layer "In4.Cu")
		(net "M_C_CPU1_SB_CS_N<0>")
	)
	(segment
		(start 83.06435 -245.51767)
		(end 66.921126 -245.51767)
		(width 0.18288)
		(layer "In4.Cu")
		(net "M_C_CPU1_SB_CS_N<0>")
	)
	(segment
		(start 51.82616 -245.341648)
		(end 31.312866 -245.341648)
		(width 0.18288)
		(layer "In4.Cu")
		(net "M_C_CPU1_SB_CS_N<0>")
	)
	(segment
		(start 31.129986 -245.93042)
		(end 30.947106 -246.1133)
		(width 0.18288)
		(layer "In4.Cu")
		(net "M_C_CPU1_SB_CS_N<0>")
	)
	(segment
		(start 29.931106 -245.341648)
		(end 29.748226 -245.524528)
		(width 0.18288)
		(layer "In4.Cu")
		(net "M_C_CPU1_SB_CS_N<0>")
	)
	(segment
		(start 66.67373 -245.270274)
		(end 65.606168 -245.270274)
		(width 0.18288)
		(layer "In4.Cu")
		(net "M_C_CPU1_SB_CS_N<0>")
	)
	(segment
		(start 31.312866 -245.341648)
		(end 31.129986 -245.524528)
		(width 0.18288)
		(layer "In4.Cu")
		(net "M_C_CPU1_SB_CS_N<0>")
	)
	(segment
		(start 58.885836 -245.161816)
		(end 58.45937 -245.161816)
		(width 0.18288)
		(layer "In4.Cu")
		(net "M_C_CPU1_SB_CS_N<0>")
	)
	(segment
		(start 91.151964 -243.598446)
		(end 91.15171 -243.598446)
		(width 0.088646)
		(layer "In4.Cu")
		(net "M_C_CPU1_SB_CS_N<0>")
	)
	(segment
		(start 86.170262 -244.726714)
		(end 86.170262 -244.73662)
		(width 0.088646)
		(layer "In4.Cu")
		(net "M_C_CPU1_SB_CS_N<0>")
	)
	(segment
		(start 29.748226 -245.93042)
		(end 29.565346 -246.1133)
		(width 0.18288)
		(layer "In4.Cu")
		(net "M_C_CPU1_SB_CS_N<0>")
	)
	(segment
		(start 29.748226 -245.524528)
		(end 29.748226 -245.93042)
		(width 0.18288)
		(layer "In4.Cu")
		(net "M_C_CPU1_SB_CS_N<0>")
	)
	(segment
		(start 52.003198 -245.518686)
		(end 51.82616 -245.341648)
		(width 0.18288)
		(layer "In4.Cu")
		(net "M_C_CPU1_SB_CS_N<0>")
	)
	(segment
		(start 30.947106 -246.1133)
		(end 30.621986 -246.1133)
		(width 0.18288)
		(layer "In4.Cu")
		(net "M_C_CPU1_SB_CS_N<0>")
	)
	(segment
		(start 83.916266 -245.799356)
		(end 83.576668 -245.799356)
		(width 0.088646)
		(layer "In4.Cu")
		(net "M_C_CPU1_SB_CS_N<0>")
	)
	(segment
		(start 59.138312 -245.414292)
		(end 58.885836 -245.161816)
		(width 0.18288)
		(layer "In4.Cu")
		(net "M_C_CPU1_SB_CS_N<0>")
	)
	(arc
		(start 87.018114 -244.247162)
		(mid 86.735412 -244.171386)
		(end 86.45271 -244.247162)
		(width 0.088646)
		(layer "In4.Cu")
		(net "M_C_CPU1_SB_CS_N<0>")
	)
	(arc
		(start 89.837768 -244.247162)
		(mid 89.563569 -244.171327)
		(end 89.287096 -244.238526)
		(width 0.088646)
		(layer "In4.Cu")
		(net "M_C_CPU1_SB_CS_N<0>")
	)
	(arc
		(start 85.138768 -245.875048)
		(mid 84.856066 -245.799272)
		(end 84.573364 -245.875048)
		(width 0.088646)
		(layer "In4.Cu")
		(net "M_C_CPU1_SB_CS_N<0>")
	)
	(arc
		(start 89.272364 -244.247162)
		(mid 89.085166 -244.297305)
		(end 88.897968 -244.247162)
		(width 0.088646)
		(layer "In4.Cu")
		(net "M_C_CPU1_SB_CS_N<0>")
	)
	(arc
		(start 88.332564 -244.247162)
		(mid 88.145366 -244.297305)
		(end 87.958168 -244.247162)
		(width 0.088646)
		(layer "In4.Cu")
		(net "M_C_CPU1_SB_CS_N<0>")
	)
	(arc
		(start 90.21191 -244.247162)
		(mid 90.024856 -244.297246)
		(end 89.837768 -244.247162)
		(width 0.088646)
		(layer "In4.Cu")
		(net "M_C_CPU1_SB_CS_N<0>")
	)
	(arc
		(start 88.897968 -244.247162)
		(mid 88.623769 -244.171327)
		(end 88.347296 -244.238526)
		(width 0.088646)
		(layer "In4.Cu")
		(net "M_C_CPU1_SB_CS_N<0>")
	)
	(arc
		(start 85.700616 -245.55069)
		(mid 85.652937 -245.73359)
		(end 85.522054 -245.869968)
		(width 0.088646)
		(layer "In4.Cu")
		(net "M_C_CPU1_SB_CS_N<0>")
	)
	(arc
		(start 84.198968 -245.875048)
		(mid 84.062602 -245.81857)
		(end 83.916266 -245.799356)
		(width 0.088646)
		(layer "In4.Cu")
		(net "M_C_CPU1_SB_CS_N<0>")
	)
	(arc
		(start 90.399616 -243.922804)
		(mid 90.349452 -244.109942)
		(end 90.212418 -244.246908)
		(width 0.088646)
		(layer "In4.Cu")
		(net "M_C_CPU1_SB_CS_N<0>")
	)
	(arc
		(start 91.15171 -243.598446)
		(mid 90.964656 -243.548362)
		(end 90.777568 -243.598446)
		(width 0.088646)
		(layer "In4.Cu")
		(net "M_C_CPU1_SB_CS_N<0>")
	)
	(arc
		(start 86.170262 -244.73662)
		(mid 86.122583 -244.91952)
		(end 85.9917 -245.055898)
		(width 0.088646)
		(layer "In4.Cu")
		(net "M_C_CPU1_SB_CS_N<0>")
	)
	(arc
		(start 87.958168 -244.247162)
		(mid 87.681355 -244.171292)
		(end 87.402924 -244.241066)
		(width 0.088646)
		(layer "In4.Cu")
		(net "M_C_CPU1_SB_CS_N<0>")
	)
	(arc
		(start 84.573364 -245.875048)
		(mid 84.386166 -245.925191)
		(end 84.198968 -245.875048)
		(width 0.088646)
		(layer "In4.Cu")
		(net "M_C_CPU1_SB_CS_N<0>")
	)
	(arc
		(start 85.98281 -245.060978)
		(mid 85.781528 -245.258465)
		(end 85.700616 -245.528592)
		(width 0.088646)
		(layer "In4.Cu")
		(net "M_C_CPU1_SB_CS_N<0>")
	)
	(arc
		(start 90.491564 -243.7638)
		(mid 90.424234 -243.830958)
		(end 90.399616 -243.922804)
		(width 0.088646)
		(layer "In4.Cu")
		(net "M_C_CPU1_SB_CS_N<0>")
	)
	(arc
		(start 85.513164 -245.875048)
		(mid 85.325966 -245.925191)
		(end 85.138768 -245.875048)
		(width 0.088646)
		(layer "In4.Cu")
		(net "M_C_CPU1_SB_CS_N<0>")
	)
	(arc
		(start 86.45271 -244.247162)
		(mid 86.248375 -244.449767)
		(end 86.170262 -244.726714)
		(width 0.088646)
		(layer "In4.Cu")
		(net "M_C_CPU1_SB_CS_N<0>")
	)
	(arc
		(start 87.39251 -244.247162)
		(mid 87.205312 -244.297305)
		(end 87.018114 -244.247162)
		(width 0.088646)
		(layer "In4.Cu")
		(net "M_C_CPU1_SB_CS_N<0>")
	)
	(segment
		(start 93.784166 -241.202972)
		(end 93.784166 -240.667286)
		(width 0.20066)
		(layer "F.Cu")
		(net "M_C_CPU1_SB_CB<7>")
	)
	(segment
		(start 29.025342 -238.966756)
		(end 29.151326 -239.09274)
		(width 0.20066)
		(layer "F.Cu")
		(net "M_C_CPU1_SB_CB<7>")
	)
	(segment
		(start 32.041592 -239.391698)
		(end 32.51708 -239.391698)
		(width 0.20066)
		(layer "F.Cu")
		(net "M_C_CPU1_SB_CB<7>")
	)
	(segment
		(start 93.783912 -241.203226)
		(end 93.784166 -241.202972)
		(width 0.20066)
		(layer "F.Cu")
		(net "M_C_CPU1_SB_CB<7>")
	)
	(segment
		(start 33.181798 -238.86287)
		(end 33.396682 -239.077754)
		(width 0.20066)
		(layer "F.Cu")
		(net "M_C_CPU1_SB_CB<7>")
	)
	(segment
		(start 27.328114 -238.966756)
		(end 29.025342 -238.966756)
		(width 0.20066)
		(layer "F.Cu")
		(net "M_C_CPU1_SB_CB<7>")
	)
	(segment
		(start 32.666178 -239.2426)
		(end 32.666178 -239.06353)
		(width 0.20066)
		(layer "F.Cu")
		(net "M_C_CPU1_SB_CB<7>")
	)
	(segment
		(start 29.513022 -239.391698)
		(end 29.899864 -239.391698)
		(width 0.101854)
		(layer "F.Cu")
		(net "M_C_CPU1_SB_CB<7>")
	)
	(segment
		(start 32.51708 -239.391698)
		(end 32.666178 -239.2426)
		(width 0.20066)
		(layer "F.Cu")
		(net "M_C_CPU1_SB_CB<7>")
	)
	(segment
		(start 32.866838 -238.86287)
		(end 33.181798 -238.86287)
		(width 0.20066)
		(layer "F.Cu")
		(net "M_C_CPU1_SB_CB<7>")
	)
	(segment
		(start 29.151326 -239.09274)
		(end 29.151326 -239.249204)
		(width 0.20066)
		(layer "F.Cu")
		(net "M_C_CPU1_SB_CB<7>")
	)
	(segment
		(start 29.151326 -239.249204)
		(end 29.29382 -239.391698)
		(width 0.20066)
		(layer "F.Cu")
		(net "M_C_CPU1_SB_CB<7>")
	)
	(segment
		(start 33.969452 -238.966756)
		(end 34.871914 -238.966756)
		(width 0.20066)
		(layer "F.Cu")
		(net "M_C_CPU1_SB_CB<7>")
	)
	(segment
		(start 32.666178 -239.06353)
		(end 32.866838 -238.86287)
		(width 0.20066)
		(layer "F.Cu")
		(net "M_C_CPU1_SB_CB<7>")
	)
	(segment
		(start 29.29382 -239.391698)
		(end 29.513022 -239.391698)
		(width 0.20066)
		(layer "F.Cu")
		(net "M_C_CPU1_SB_CB<7>")
	)
	(segment
		(start 33.858454 -239.077754)
		(end 33.969452 -238.966756)
		(width 0.20066)
		(layer "F.Cu")
		(net "M_C_CPU1_SB_CB<7>")
	)
	(segment
		(start 29.899864 -239.391698)
		(end 31.972758 -239.391698)
		(width 0.1016)
		(layer "F.Cu")
		(net "M_C_CPU1_SB_CB<7>")
	)
	(segment
		(start 33.396682 -239.077754)
		(end 33.858454 -239.077754)
		(width 0.20066)
		(layer "F.Cu")
		(net "M_C_CPU1_SB_CB<7>")
	)
	(segment
		(start 31.972758 -239.391698)
		(end 32.041592 -239.391698)
		(width 0.101854)
		(layer "F.Cu")
		(net "M_C_CPU1_SB_CB<7>")
	)
	(segment
		(start 35.976814 -238.966756)
		(end 34.871914 -238.966756)
		(width 0.20066)
		(layer "F.Cu")
		(net "M_C_CPU1_SB_CB<7>")
	)
	(segment
		(start 38.847776 -239.577626)
		(end 38.664896 -239.394746)
		(width 0.18288)
		(layer "In4.Cu")
		(net "M_C_CPU1_SB_CB<7>")
	)
	(segment
		(start 42.098214 -239.818672)
		(end 41.915334 -239.635792)
		(width 0.18288)
		(layer "In4.Cu")
		(net "M_C_CPU1_SB_CB<7>")
	)
	(segment
		(start 44.412662 -239.394492)
		(end 44.215812 -239.197642)
		(width 0.18288)
		(layer "In4.Cu")
		(net "M_C_CPU1_SB_CB<7>")
	)
	(segment
		(start 91.722956 -240.339372)
		(end 91.717114 -240.342928)
		(width 0.088646)
		(layer "In4.Cu")
		(net "M_C_CPU1_SB_CB<7>")
	)
	(segment
		(start 49.217326 -240.240312)
		(end 46.319186 -240.240312)
		(width 0.18288)
		(layer "In4.Cu")
		(net "M_C_CPU1_SB_CB<7>")
	)
	(segment
		(start 87.110316 -241.471196)
		(end 87.110316 -241.481102)
		(width 0.088646)
		(layer "In4.Cu")
		(net "M_C_CPU1_SB_CB<7>")
	)
	(segment
		(start 39.793418 -239.577626)
		(end 38.847776 -239.577626)
		(width 0.18288)
		(layer "In4.Cu")
		(net "M_C_CPU1_SB_CB<7>")
	)
	(segment
		(start 83.064096 -242.08359)
		(end 70.167754 -242.08359)
		(width 0.18288)
		(layer "In4.Cu")
		(net "M_C_CPU1_SB_CB<7>")
	)
	(segment
		(start 38.156896 -238.770414)
		(end 37.974016 -238.953294)
		(width 0.18288)
		(layer "In4.Cu")
		(net "M_C_CPU1_SB_CB<7>")
	)
	(segment
		(start 93.784166 -240.667286)
		(end 93.783912 -240.66754)
		(width 0.088646)
		(layer "In4.Cu")
		(net "M_C_CPU1_SB_CB<7>")
	)
	(segment
		(start 88.897714 -240.991644)
		(end 88.893142 -240.989104)
		(width 0.088646)
		(layer "In4.Cu")
		(net "M_C_CPU1_SB_CB<7>")
	)
	(segment
		(start 83.326986 -242.08359)
		(end 83.064096 -242.08359)
		(width 0.088646)
		(layer "In4.Cu")
		(net "M_C_CPU1_SB_CB<7>")
	)
	(segment
		(start 91.54414 -240.512346)
		(end 91.42222 -240.726722)
		(width 0.088646)
		(layer "In4.Cu")
		(net "M_C_CPU1_SB_CB<7>")
	)
	(segment
		(start 45.473366 -239.394492)
		(end 44.412662 -239.394492)
		(width 0.18288)
		(layer "In4.Cu")
		(net "M_C_CPU1_SB_CB<7>")
	)
	(segment
		(start 55.734204 -238.714026)
		(end 55.056532 -239.391698)
		(width 0.18288)
		(layer "In4.Cu")
		(net "M_C_CPU1_SB_CB<7>")
	)
	(segment
		(start 62.886844 -239.573816)
		(end 61.88964 -239.573816)
		(width 0.18288)
		(layer "In4.Cu")
		(net "M_C_CPU1_SB_CB<7>")
	)
	(segment
		(start 86.931754 -241.80038)
		(end 86.922864 -241.80546)
		(width 0.088646)
		(layer "In4.Cu")
		(net "M_C_CPU1_SB_CB<7>")
	)
	(segment
		(start 61.88964 -239.573816)
		(end 60.793884 -238.47806)
		(width 0.18288)
		(layer "In4.Cu")
		(net "M_C_CPU1_SB_CB<7>")
	)
	(segment
		(start 41.915334 -239.635792)
		(end 41.915334 -238.801656)
		(width 0.18288)
		(layer "In4.Cu")
		(net "M_C_CPU1_SB_CB<7>")
	)
	(segment
		(start 70.167754 -242.08359)
		(end 67.474592 -239.390428)
		(width 0.18288)
		(layer "In4.Cu")
		(net "M_C_CPU1_SB_CB<7>")
	)
	(segment
		(start 44.215812 -238.803942)
		(end 44.030646 -238.618776)
		(width 0.18288)
		(layer "In4.Cu")
		(net "M_C_CPU1_SB_CB<7>")
	)
	(segment
		(start 60.793884 -238.47806)
		(end 59.23788 -238.47806)
		(width 0.18288)
		(layer "In4.Cu")
		(net "M_C_CPU1_SB_CB<7>")
	)
	(segment
		(start 41.915334 -238.801656)
		(end 41.732454 -238.618776)
		(width 0.18288)
		(layer "In4.Cu")
		(net "M_C_CPU1_SB_CB<7>")
	)
	(segment
		(start 93.427804 -240.571782)
		(end 93.031564 -240.342674)
		(width 0.088646)
		(layer "In4.Cu")
		(net "M_C_CPU1_SB_CB<7>")
	)
	(segment
		(start 40.752268 -238.618776)
		(end 39.793418 -239.577626)
		(width 0.18288)
		(layer "In4.Cu")
		(net "M_C_CPU1_SB_CB<7>")
	)
	(segment
		(start 59.23788 -238.47806)
		(end 59.001914 -238.714026)
		(width 0.18288)
		(layer "In4.Cu")
		(net "M_C_CPU1_SB_CB<7>")
	)
	(segment
		(start 84.582 -242.614196)
		(end 84.57311 -242.619276)
		(width 0.088646)
		(layer "In4.Cu")
		(net "M_C_CPU1_SB_CB<7>")
	)
	(segment
		(start 46.319186 -240.240312)
		(end 45.473366 -239.394492)
		(width 0.18288)
		(layer "In4.Cu")
		(net "M_C_CPU1_SB_CB<7>")
	)
	(segment
		(start 91.717114 -240.342928)
		(end 91.711272 -240.34623)
		(width 0.088646)
		(layer "In4.Cu")
		(net "M_C_CPU1_SB_CB<7>")
	)
	(segment
		(start 42.606214 -239.635792)
		(end 42.423334 -239.818672)
		(width 0.18288)
		(layer "In4.Cu")
		(net "M_C_CPU1_SB_CB<7>")
	)
	(segment
		(start 44.030646 -238.618776)
		(end 42.789094 -238.618776)
		(width 0.18288)
		(layer "In4.Cu")
		(net "M_C_CPU1_SB_CB<7>")
	)
	(segment
		(start 90.783156 -240.994946)
		(end 90.771472 -240.988342)
		(width 0.088646)
		(layer "In4.Cu")
		(net "M_C_CPU1_SB_CB<7>")
	)
	(segment
		(start 44.215812 -239.197642)
		(end 44.215812 -238.803942)
		(width 0.18288)
		(layer "In4.Cu")
		(net "M_C_CPU1_SB_CB<7>")
	)
	(segment
		(start 42.423334 -239.818672)
		(end 42.098214 -239.818672)
		(width 0.18288)
		(layer "In4.Cu")
		(net "M_C_CPU1_SB_CB<7>")
	)
	(segment
		(start 89.843356 -240.994946)
		(end 89.831672 -240.988342)
		(width 0.088646)
		(layer "In4.Cu")
		(net "M_C_CPU1_SB_CB<7>")
	)
	(segment
		(start 67.474592 -239.390428)
		(end 63.070232 -239.390428)
		(width 0.18288)
		(layer "In4.Cu")
		(net "M_C_CPU1_SB_CB<7>")
	)
	(segment
		(start 83.916266 -242.543584)
		(end 83.78698 -242.543584)
		(width 0.088646)
		(layer "In4.Cu")
		(net "M_C_CPU1_SB_CB<7>")
	)
	(segment
		(start 41.732454 -238.618776)
		(end 40.752268 -238.618776)
		(width 0.18288)
		(layer "In4.Cu")
		(net "M_C_CPU1_SB_CB<7>")
	)
	(segment
		(start 38.664896 -238.953294)
		(end 38.482016 -238.770414)
		(width 0.18288)
		(layer "In4.Cu")
		(net "M_C_CPU1_SB_CB<7>")
	)
	(segment
		(start 85.057996 -241.796824)
		(end 85.043264 -241.80546)
		(width 0.088646)
		(layer "In4.Cu")
		(net "M_C_CPU1_SB_CB<7>")
	)
	(segment
		(start 37.791136 -239.577626)
		(end 36.587684 -239.577626)
		(width 0.18288)
		(layer "In4.Cu")
		(net "M_C_CPU1_SB_CB<7>")
	)
	(segment
		(start 83.78698 -242.543584)
		(end 83.326986 -242.08359)
		(width 0.088646)
		(layer "In4.Cu")
		(net "M_C_CPU1_SB_CB<7>")
	)
	(segment
		(start 38.482016 -238.770414)
		(end 38.156896 -238.770414)
		(width 0.18288)
		(layer "In4.Cu")
		(net "M_C_CPU1_SB_CB<7>")
	)
	(segment
		(start 37.974016 -238.953294)
		(end 37.974016 -239.394746)
		(width 0.18288)
		(layer "In4.Cu")
		(net "M_C_CPU1_SB_CB<7>")
	)
	(segment
		(start 55.056532 -239.391698)
		(end 50.06594 -239.391698)
		(width 0.18288)
		(layer "In4.Cu")
		(net "M_C_CPU1_SB_CB<7>")
	)
	(segment
		(start 38.664896 -239.394746)
		(end 38.664896 -238.953294)
		(width 0.18288)
		(layer "In4.Cu")
		(net "M_C_CPU1_SB_CB<7>")
	)
	(segment
		(start 42.789094 -238.618776)
		(end 42.606214 -238.801656)
		(width 0.18288)
		(layer "In4.Cu")
		(net "M_C_CPU1_SB_CB<7>")
	)
	(segment
		(start 63.070232 -239.390428)
		(end 62.886844 -239.573816)
		(width 0.18288)
		(layer "In4.Cu")
		(net "M_C_CPU1_SB_CB<7>")
	)
	(segment
		(start 42.606214 -238.801656)
		(end 42.606214 -239.635792)
		(width 0.18288)
		(layer "In4.Cu")
		(net "M_C_CPU1_SB_CB<7>")
	)
	(segment
		(start 36.587684 -239.577626)
		(end 35.976814 -238.966756)
		(width 0.18288)
		(layer "In4.Cu")
		(net "M_C_CPU1_SB_CB<7>")
	)
	(segment
		(start 92.656914 -240.342928)
		(end 92.651072 -240.34623)
		(width 0.088646)
		(layer "In4.Cu")
		(net "M_C_CPU1_SB_CB<7>")
	)
	(segment
		(start 88.903556 -240.994946)
		(end 88.897714 -240.991644)
		(width 0.088646)
		(layer "In4.Cu")
		(net "M_C_CPU1_SB_CB<7>")
	)
	(segment
		(start 85.043264 -241.80546)
		(end 85.037168 -241.809016)
		(width 0.088646)
		(layer "In4.Cu")
		(net "M_C_CPU1_SB_CB<7>")
	)
	(segment
		(start 92.662756 -240.339372)
		(end 92.656914 -240.342928)
		(width 0.088646)
		(layer "In4.Cu")
		(net "M_C_CPU1_SB_CB<7>")
	)
	(segment
		(start 50.06594 -239.391698)
		(end 49.217326 -240.240312)
		(width 0.18288)
		(layer "In4.Cu")
		(net "M_C_CPU1_SB_CB<7>")
	)
	(segment
		(start 37.974016 -239.394746)
		(end 37.791136 -239.577626)
		(width 0.18288)
		(layer "In4.Cu")
		(net "M_C_CPU1_SB_CB<7>")
	)
	(segment
		(start 59.001914 -238.714026)
		(end 55.734204 -238.714026)
		(width 0.18288)
		(layer "In4.Cu")
		(net "M_C_CPU1_SB_CB<7>")
	)
	(arc
		(start 87.110316 -241.481102)
		(mid 87.062637 -241.664002)
		(end 86.931754 -241.80038)
		(width 0.088646)
		(layer "In4.Cu")
		(net "M_C_CPU1_SB_CB<7>")
	)
	(arc
		(start 89.831672 -240.988342)
		(mid 89.551567 -240.9159)
		(end 89.272364 -240.991644)
		(width 0.088646)
		(layer "In4.Cu")
		(net "M_C_CPU1_SB_CB<7>")
	)
	(arc
		(start 84.57311 -242.619276)
		(mid 84.385912 -242.669419)
		(end 84.198714 -242.619276)
		(width 0.088646)
		(layer "In4.Cu")
		(net "M_C_CPU1_SB_CB<7>")
	)
	(arc
		(start 85.608668 -241.80546)
		(mid 85.334469 -241.729625)
		(end 85.057996 -241.796824)
		(width 0.088646)
		(layer "In4.Cu")
		(net "M_C_CPU1_SB_CB<7>")
	)
	(arc
		(start 91.711272 -240.34623)
		(mid 91.659927 -240.380495)
		(end 91.613482 -240.42116)
		(width 0.088646)
		(layer "In4.Cu")
		(net "M_C_CPU1_SB_CB<7>")
	)
	(arc
		(start 90.771472 -240.988342)
		(mid 90.491367 -240.9159)
		(end 90.212164 -240.991644)
		(width 0.088646)
		(layer "In4.Cu")
		(net "M_C_CPU1_SB_CB<7>")
	)
	(arc
		(start 84.198714 -242.619276)
		(mid 84.062471 -242.56283)
		(end 83.916266 -242.543584)
		(width 0.088646)
		(layer "In4.Cu")
		(net "M_C_CPU1_SB_CB<7>")
	)
	(arc
		(start 92.091764 -240.342674)
		(mid 91.90781 -240.292579)
		(end 91.722956 -240.339372)
		(width 0.088646)
		(layer "In4.Cu")
		(net "M_C_CPU1_SB_CB<7>")
	)
	(arc
		(start 91.151964 -240.991644)
		(mid 90.96801 -241.041773)
		(end 90.783156 -240.994946)
		(width 0.088646)
		(layer "In4.Cu")
		(net "M_C_CPU1_SB_CB<7>")
	)
	(arc
		(start 86.548468 -241.80546)
		(mid 86.265766 -241.729684)
		(end 85.983064 -241.80546)
		(width 0.088646)
		(layer "In4.Cu")
		(net "M_C_CPU1_SB_CB<7>")
	)
	(arc
		(start 93.783912 -240.66754)
		(mid 93.599559 -240.643104)
		(end 93.427804 -240.571782)
		(width 0.088646)
		(layer "In4.Cu")
		(net "M_C_CPU1_SB_CB<7>")
	)
	(arc
		(start 91.42222 -240.726722)
		(mid 91.374178 -240.799488)
		(end 91.31681 -240.865152)
		(width 0.088646)
		(layer "In4.Cu")
		(net "M_C_CPU1_SB_CB<7>")
	)
	(arc
		(start 88.332564 -240.991644)
		(mid 88.145366 -241.041787)
		(end 87.958168 -240.991644)
		(width 0.088646)
		(layer "In4.Cu")
		(net "M_C_CPU1_SB_CB<7>")
	)
	(arc
		(start 90.212164 -240.991644)
		(mid 90.02821 -241.041773)
		(end 89.843356 -240.994946)
		(width 0.088646)
		(layer "In4.Cu")
		(net "M_C_CPU1_SB_CB<7>")
	)
	(arc
		(start 87.958168 -240.991644)
		(mid 87.675466 -240.915868)
		(end 87.392764 -240.991644)
		(width 0.088646)
		(layer "In4.Cu")
		(net "M_C_CPU1_SB_CB<7>")
	)
	(arc
		(start 85.037168 -241.809016)
		(mid 84.834581 -242.015367)
		(end 84.760562 -242.294918)
		(width 0.088646)
		(layer "In4.Cu")
		(net "M_C_CPU1_SB_CB<7>")
	)
	(arc
		(start 84.760562 -242.294918)
		(mid 84.712883 -242.477818)
		(end 84.582 -242.614196)
		(width 0.088646)
		(layer "In4.Cu")
		(net "M_C_CPU1_SB_CB<7>")
	)
	(arc
		(start 91.31681 -240.865152)
		(mid 91.23852 -240.933782)
		(end 91.151964 -240.991644)
		(width 0.088646)
		(layer "In4.Cu")
		(net "M_C_CPU1_SB_CB<7>")
	)
	(arc
		(start 85.983064 -241.80546)
		(mid 85.795866 -241.855603)
		(end 85.608668 -241.80546)
		(width 0.088646)
		(layer "In4.Cu")
		(net "M_C_CPU1_SB_CB<7>")
	)
	(arc
		(start 93.031564 -240.342674)
		(mid 92.84761 -240.292579)
		(end 92.662756 -240.339372)
		(width 0.088646)
		(layer "In4.Cu")
		(net "M_C_CPU1_SB_CB<7>")
	)
	(arc
		(start 87.392764 -240.991644)
		(mid 87.188429 -241.194249)
		(end 87.110316 -241.471196)
		(width 0.088646)
		(layer "In4.Cu")
		(net "M_C_CPU1_SB_CB<7>")
	)
	(arc
		(start 89.272364 -240.991644)
		(mid 89.08841 -241.041773)
		(end 88.903556 -240.994946)
		(width 0.088646)
		(layer "In4.Cu")
		(net "M_C_CPU1_SB_CB<7>")
	)
	(arc
		(start 92.651072 -240.34623)
		(mid 92.370937 -240.418546)
		(end 92.091764 -240.342674)
		(width 0.088646)
		(layer "In4.Cu")
		(net "M_C_CPU1_SB_CB<7>")
	)
	(arc
		(start 86.922864 -241.80546)
		(mid 86.735666 -241.855603)
		(end 86.548468 -241.80546)
		(width 0.088646)
		(layer "In4.Cu")
		(net "M_C_CPU1_SB_CB<7>")
	)
	(arc
		(start 88.893142 -240.989104)
		(mid 88.612507 -240.915936)
		(end 88.332564 -240.991644)
		(width 0.088646)
		(layer "In4.Cu")
		(net "M_C_CPU1_SB_CB<7>")
	)
	(arc
		(start 91.613482 -240.42116)
		(mid 91.575742 -240.464419)
		(end 91.54414 -240.512346)
		(width 0.088646)
		(layer "In4.Cu")
		(net "M_C_CPU1_SB_CB<7>")
	)
	(segment
		(start 31.972758 -240.241836)
		(end 32.041338 -240.241836)
		(width 0.101854)
		(layer "F.Cu")
		(net "M_C_CPU1_SB_CB<6>")
	)
	(segment
		(start 93.314012 -242.016788)
		(end 93.314012 -241.481102)
		(width 0.20066)
		(layer "F.Cu")
		(net "M_C_CPU1_SB_CB<6>")
	)
	(segment
		(start 32.585406 -240.241836)
		(end 32.74949 -240.40592)
		(width 0.20066)
		(layer "F.Cu")
		(net "M_C_CPU1_SB_CB<6>")
	)
	(segment
		(start 29.512768 -240.241836)
		(end 29.912818 -240.241836)
		(width 0.101854)
		(layer "F.Cu")
		(net "M_C_CPU1_SB_CB<6>")
	)
	(segment
		(start 32.74949 -240.711228)
		(end 32.984694 -240.946432)
		(width 0.20066)
		(layer "F.Cu")
		(net "M_C_CPU1_SB_CB<6>")
	)
	(segment
		(start 28.475178 -240.666778)
		(end 28.90012 -240.241836)
		(width 0.20066)
		(layer "F.Cu")
		(net "M_C_CPU1_SB_CB<6>")
	)
	(segment
		(start 28.90012 -240.241836)
		(end 29.512768 -240.241836)
		(width 0.20066)
		(layer "F.Cu")
		(net "M_C_CPU1_SB_CB<6>")
	)
	(segment
		(start 27.328114 -240.666778)
		(end 28.475178 -240.666778)
		(width 0.20066)
		(layer "F.Cu")
		(net "M_C_CPU1_SB_CB<6>")
	)
	(segment
		(start 29.912818 -240.241836)
		(end 31.972758 -240.241836)
		(width 0.1016)
		(layer "F.Cu")
		(net "M_C_CPU1_SB_CB<6>")
	)
	(segment
		(start 32.041338 -240.241836)
		(end 32.585406 -240.241836)
		(width 0.20066)
		(layer "F.Cu")
		(net "M_C_CPU1_SB_CB<6>")
	)
	(segment
		(start 35.976814 -240.666778)
		(end 34.871914 -240.666778)
		(width 0.20066)
		(layer "F.Cu")
		(net "M_C_CPU1_SB_CB<6>")
	)
	(segment
		(start 32.74949 -240.40592)
		(end 32.74949 -240.711228)
		(width 0.20066)
		(layer "F.Cu")
		(net "M_C_CPU1_SB_CB<6>")
	)
	(segment
		(start 33.277556 -240.946432)
		(end 33.55721 -240.666778)
		(width 0.20066)
		(layer "F.Cu")
		(net "M_C_CPU1_SB_CB<6>")
	)
	(segment
		(start 32.984694 -240.946432)
		(end 33.277556 -240.946432)
		(width 0.20066)
		(layer "F.Cu")
		(net "M_C_CPU1_SB_CB<6>")
	)
	(segment
		(start 93.314266 -242.017042)
		(end 93.314012 -242.016788)
		(width 0.20066)
		(layer "F.Cu")
		(net "M_C_CPU1_SB_CB<6>")
	)
	(segment
		(start 33.55721 -240.666778)
		(end 34.871914 -240.666778)
		(width 0.20066)
		(layer "F.Cu")
		(net "M_C_CPU1_SB_CB<6>")
	)
	(segment
		(start 50.182018 -241.09172)
		(end 49.329086 -241.944652)
		(width 0.18288)
		(layer "In4.Cu")
		(net "M_C_CPU1_SB_CB<6>")
	)
	(segment
		(start 83.758278 -243.483892)
		(end 83.353656 -243.07927)
		(width 0.088646)
		(layer "In4.Cu")
		(net "M_C_CPU1_SB_CB<6>")
	)
	(segment
		(start 65.010792 -241.397536)
		(end 64.685672 -241.397536)
		(width 0.18288)
		(layer "In4.Cu")
		(net "M_C_CPU1_SB_CB<6>")
	)
	(segment
		(start 86.078568 -242.619276)
		(end 86.068154 -242.61318)
		(width 0.088646)
		(layer "In4.Cu")
		(net "M_C_CPU1_SB_CB<6>")
	)
	(segment
		(start 51.618642 -241.302794)
		(end 51.407568 -241.09172)
		(width 0.18288)
		(layer "In4.Cu")
		(net "M_C_CPU1_SB_CB<6>")
	)
	(segment
		(start 42.64025 -241.048794)
		(end 42.64025 -241.36731)
		(width 0.18288)
		(layer "In4.Cu")
		(net "M_C_CPU1_SB_CB<6>")
	)
	(segment
		(start 65.376552 -240.888266)
		(end 65.193672 -241.071146)
		(width 0.18288)
		(layer "In4.Cu")
		(net "M_C_CPU1_SB_CB<6>")
	)
	(segment
		(start 64.319912 -240.888266)
		(end 63.304674 -240.888266)
		(width 0.18288)
		(layer "In4.Cu")
		(net "M_C_CPU1_SB_CB<6>")
	)
	(segment
		(start 87.862664 -241.80546)
		(end 87.856568 -241.809016)
		(width 0.088646)
		(layer "In4.Cu")
		(net "M_C_CPU1_SB_CB<6>")
	)
	(segment
		(start 91.6305 -241.80038)
		(end 91.62161 -241.80546)
		(width 0.088646)
		(layer "In4.Cu")
		(net "M_C_CPU1_SB_CB<6>")
	)
	(segment
		(start 38.589458 -241.215926)
		(end 38.589458 -240.791492)
		(width 0.18288)
		(layer "In4.Cu")
		(net "M_C_CPU1_SB_CB<6>")
	)
	(segment
		(start 64.502792 -241.071146)
		(end 64.319912 -240.888266)
		(width 0.18288)
		(layer "In4.Cu")
		(net "M_C_CPU1_SB_CB<6>")
	)
	(segment
		(start 90.307414 -241.80546)
		(end 90.292682 -241.796824)
		(width 0.088646)
		(layer "In4.Cu")
		(net "M_C_CPU1_SB_CB<6>")
	)
	(segment
		(start 38.589458 -240.791492)
		(end 38.406578 -240.608612)
		(width 0.18288)
		(layer "In4.Cu")
		(net "M_C_CPU1_SB_CB<6>")
	)
	(segment
		(start 87.018114 -242.619276)
		(end 87.0077 -242.61318)
		(width 0.088646)
		(layer "In4.Cu")
		(net "M_C_CPU1_SB_CB<6>")
	)
	(segment
		(start 58.435748 -240.566448)
		(end 57.756552 -239.887252)
		(width 0.18288)
		(layer "In4.Cu")
		(net "M_C_CPU1_SB_CB<6>")
	)
	(segment
		(start 45.975778 -241.944652)
		(end 45.122846 -241.09172)
		(width 0.18288)
		(layer "In4.Cu")
		(net "M_C_CPU1_SB_CB<6>")
	)
	(segment
		(start 60.750196 -240.155984)
		(end 60.590176 -239.995964)
		(width 0.18288)
		(layer "In4.Cu")
		(net "M_C_CPU1_SB_CB<6>")
	)
	(segment
		(start 84.118196 -243.42471)
		(end 84.103464 -243.433346)
		(width 0.088646)
		(layer "In4.Cu")
		(net "M_C_CPU1_SB_CB<6>")
	)
	(segment
		(start 65.926208 -240.888012)
		(end 65.925954 -240.888266)
		(width 0.18288)
		(layer "In4.Cu")
		(net "M_C_CPU1_SB_CB<6>")
	)
	(segment
		(start 53.008022 -240.843054)
		(end 53.008022 -241.119914)
		(width 0.18288)
		(layer "In4.Cu")
		(net "M_C_CPU1_SB_CB<6>")
	)
	(segment
		(start 42.82313 -240.865914)
		(end 42.64025 -241.048794)
		(width 0.18288)
		(layer "In4.Cu")
		(net "M_C_CPU1_SB_CB<6>")
	)
	(segment
		(start 38.081458 -240.608612)
		(end 37.898578 -240.791492)
		(width 0.18288)
		(layer "In4.Cu")
		(net "M_C_CPU1_SB_CB<6>")
	)
	(segment
		(start 44.1071 -240.865914)
		(end 42.82313 -240.865914)
		(width 0.18288)
		(layer "In4.Cu")
		(net "M_C_CPU1_SB_CB<6>")
	)
	(segment
		(start 63.304674 -240.888266)
		(end 62.930024 -241.262916)
		(width 0.18288)
		(layer "In4.Cu")
		(net "M_C_CPU1_SB_CB<6>")
	)
	(segment
		(start 37.898578 -241.215926)
		(end 37.715698 -241.398806)
		(width 0.18288)
		(layer "In4.Cu")
		(net "M_C_CPU1_SB_CB<6>")
	)
	(segment
		(start 83.06435 -243.07927)
		(end 69.726302 -243.07927)
		(width 0.18288)
		(layer "In4.Cu")
		(net "M_C_CPU1_SB_CB<6>")
	)
	(segment
		(start 42.64025 -241.36731)
		(end 42.45737 -241.55019)
		(width 0.18288)
		(layer "In4.Cu")
		(net "M_C_CPU1_SB_CB<6>")
	)
	(segment
		(start 44.332906 -241.09172)
		(end 44.1071 -240.865914)
		(width 0.18288)
		(layer "In4.Cu")
		(net "M_C_CPU1_SB_CB<6>")
	)
	(segment
		(start 69.726302 -243.07927)
		(end 67.535044 -240.888012)
		(width 0.18288)
		(layer "In4.Cu")
		(net "M_C_CPU1_SB_CB<6>")
	)
	(segment
		(start 60.590176 -239.995964)
		(end 59.558936 -239.995964)
		(width 0.18288)
		(layer "In4.Cu")
		(net "M_C_CPU1_SB_CB<6>")
	)
	(segment
		(start 53.190902 -240.660174)
		(end 53.008022 -240.843054)
		(width 0.18288)
		(layer "In4.Cu")
		(net "M_C_CPU1_SB_CB<6>")
	)
	(segment
		(start 58.988452 -240.566448)
		(end 58.435748 -240.566448)
		(width 0.18288)
		(layer "In4.Cu")
		(net "M_C_CPU1_SB_CB<6>")
	)
	(segment
		(start 87.407496 -242.61064)
		(end 87.39251 -242.619276)
		(width 0.088646)
		(layer "In4.Cu")
		(net "M_C_CPU1_SB_CB<6>")
	)
	(segment
		(start 92.106496 -240.983008)
		(end 92.091764 -240.991644)
		(width 0.088646)
		(layer "In4.Cu")
		(net "M_C_CPU1_SB_CB<6>")
	)
	(segment
		(start 53.698902 -241.119914)
		(end 53.698902 -240.843054)
		(width 0.18288)
		(layer "In4.Cu")
		(net "M_C_CPU1_SB_CB<6>")
	)
	(segment
		(start 65.925954 -240.888266)
		(end 65.376552 -240.888266)
		(width 0.18288)
		(layer "In4.Cu")
		(net "M_C_CPU1_SB_CB<6>")
	)
	(segment
		(start 42.13225 -241.55019)
		(end 41.94937 -241.36731)
		(width 0.18288)
		(layer "In4.Cu")
		(net "M_C_CPU1_SB_CB<6>")
	)
	(segment
		(start 38.406578 -240.608612)
		(end 38.081458 -240.608612)
		(width 0.18288)
		(layer "In4.Cu")
		(net "M_C_CPU1_SB_CB<6>")
	)
	(segment
		(start 91.247214 -241.80546)
		(end 91.232482 -241.796824)
		(width 0.088646)
		(layer "In4.Cu")
		(net "M_C_CPU1_SB_CB<6>")
	)
	(segment
		(start 85.230716 -243.08689)
		(end 85.230716 -243.108988)
		(width 0.088646)
		(layer "In4.Cu")
		(net "M_C_CPU1_SB_CB<6>")
	)
	(segment
		(start 42.45737 -241.55019)
		(end 42.13225 -241.55019)
		(width 0.18288)
		(layer "In4.Cu")
		(net "M_C_CPU1_SB_CB<6>")
	)
	(segment
		(start 93.314012 -241.481102)
		(end 93.001338 -241.481102)
		(width 0.088646)
		(layer "In4.Cu")
		(net "M_C_CPU1_SB_CB<6>")
	)
	(segment
		(start 64.685672 -241.397536)
		(end 64.502792 -241.214656)
		(width 0.18288)
		(layer "In4.Cu")
		(net "M_C_CPU1_SB_CB<6>")
	)
	(segment
		(start 56.776112 -240.25479)
		(end 54.246272 -241.302794)
		(width 0.18288)
		(layer "In4.Cu")
		(net "M_C_CPU1_SB_CB<6>")
	)
	(segment
		(start 36.708842 -241.398806)
		(end 35.976814 -240.666778)
		(width 0.18288)
		(layer "In4.Cu")
		(net "M_C_CPU1_SB_CB<6>")
	)
	(segment
		(start 88.427814 -241.80546)
		(end 88.4174 -241.799364)
		(width 0.088646)
		(layer "In4.Cu")
		(net "M_C_CPU1_SB_CB<6>")
	)
	(segment
		(start 54.246272 -241.302794)
		(end 53.881782 -241.302794)
		(width 0.18288)
		(layer "In4.Cu")
		(net "M_C_CPU1_SB_CB<6>")
	)
	(segment
		(start 53.516022 -240.660174)
		(end 53.190902 -240.660174)
		(width 0.18288)
		(layer "In4.Cu")
		(net "M_C_CPU1_SB_CB<6>")
	)
	(segment
		(start 45.122846 -241.09172)
		(end 44.332906 -241.09172)
		(width 0.18288)
		(layer "In4.Cu")
		(net "M_C_CPU1_SB_CB<6>")
	)
	(segment
		(start 49.329086 -241.944652)
		(end 45.975778 -241.944652)
		(width 0.18288)
		(layer "In4.Cu")
		(net "M_C_CPU1_SB_CB<6>")
	)
	(segment
		(start 37.715698 -241.398806)
		(end 36.708842 -241.398806)
		(width 0.18288)
		(layer "In4.Cu")
		(net "M_C_CPU1_SB_CB<6>")
	)
	(segment
		(start 51.407568 -241.09172)
		(end 50.182018 -241.09172)
		(width 0.18288)
		(layer "In4.Cu")
		(net "M_C_CPU1_SB_CB<6>")
	)
	(segment
		(start 85.052154 -243.428266)
		(end 85.043264 -243.433346)
		(width 0.088646)
		(layer "In4.Cu")
		(net "M_C_CPU1_SB_CB<6>")
	)
	(segment
		(start 40.25138 -241.398806)
		(end 38.772338 -241.398806)
		(width 0.18288)
		(layer "In4.Cu")
		(net "M_C_CPU1_SB_CB<6>")
	)
	(segment
		(start 41.94937 -241.36731)
		(end 41.94937 -241.048794)
		(width 0.18288)
		(layer "In4.Cu")
		(net "M_C_CPU1_SB_CB<6>")
	)
	(segment
		(start 53.881782 -241.302794)
		(end 53.698902 -241.119914)
		(width 0.18288)
		(layer "In4.Cu")
		(net "M_C_CPU1_SB_CB<6>")
	)
	(segment
		(start 53.008022 -241.119914)
		(end 52.825142 -241.302794)
		(width 0.18288)
		(layer "In4.Cu")
		(net "M_C_CPU1_SB_CB<6>")
	)
	(segment
		(start 57.756552 -239.887252)
		(end 57.14365 -239.887252)
		(width 0.18288)
		(layer "In4.Cu")
		(net "M_C_CPU1_SB_CB<6>")
	)
	(segment
		(start 38.772338 -241.398806)
		(end 38.589458 -241.215926)
		(width 0.18288)
		(layer "In4.Cu")
		(net "M_C_CPU1_SB_CB<6>")
	)
	(segment
		(start 64.502792 -241.214656)
		(end 64.502792 -241.071146)
		(width 0.18288)
		(layer "In4.Cu")
		(net "M_C_CPU1_SB_CB<6>")
	)
	(segment
		(start 57.14365 -239.887252)
		(end 56.776112 -240.25479)
		(width 0.18288)
		(layer "In4.Cu")
		(net "M_C_CPU1_SB_CB<6>")
	)
	(segment
		(start 65.193672 -241.214656)
		(end 65.010792 -241.397536)
		(width 0.18288)
		(layer "In4.Cu")
		(net "M_C_CPU1_SB_CB<6>")
	)
	(segment
		(start 53.698902 -240.843054)
		(end 53.516022 -240.660174)
		(width 0.18288)
		(layer "In4.Cu")
		(net "M_C_CPU1_SB_CB<6>")
	)
	(segment
		(start 60.750196 -240.872772)
		(end 60.750196 -240.155984)
		(width 0.18288)
		(layer "In4.Cu")
		(net "M_C_CPU1_SB_CB<6>")
	)
	(segment
		(start 62.930024 -241.262916)
		(end 61.14034 -241.262916)
		(width 0.18288)
		(layer "In4.Cu")
		(net "M_C_CPU1_SB_CB<6>")
	)
	(segment
		(start 40.784272 -240.865914)
		(end 40.25138 -241.398806)
		(width 0.18288)
		(layer "In4.Cu")
		(net "M_C_CPU1_SB_CB<6>")
	)
	(segment
		(start 83.353656 -243.07927)
		(end 83.06435 -243.07927)
		(width 0.088646)
		(layer "In4.Cu")
		(net "M_C_CPU1_SB_CB<6>")
	)
	(segment
		(start 41.76649 -240.865914)
		(end 40.784272 -240.865914)
		(width 0.18288)
		(layer "In4.Cu")
		(net "M_C_CPU1_SB_CB<6>")
	)
	(segment
		(start 92.091764 -240.991644)
		(end 92.085668 -240.9952)
		(width 0.088646)
		(layer "In4.Cu")
		(net "M_C_CPU1_SB_CB<6>")
	)
	(segment
		(start 83.916266 -243.483892)
		(end 83.758278 -243.483892)
		(width 0.088646)
		(layer "In4.Cu")
		(net "M_C_CPU1_SB_CB<6>")
	)
	(segment
		(start 61.14034 -241.262916)
		(end 60.750196 -240.872772)
		(width 0.18288)
		(layer "In4.Cu")
		(net "M_C_CPU1_SB_CB<6>")
	)
	(segment
		(start 89.367614 -241.80546)
		(end 89.352882 -241.796824)
		(width 0.088646)
		(layer "In4.Cu")
		(net "M_C_CPU1_SB_CB<6>")
	)
	(segment
		(start 37.898578 -240.791492)
		(end 37.898578 -241.215926)
		(width 0.18288)
		(layer "In4.Cu")
		(net "M_C_CPU1_SB_CB<6>")
	)
	(segment
		(start 93.001338 -241.481102)
		(end 92.935806 -241.41557)
		(width 0.088646)
		(layer "In4.Cu")
		(net "M_C_CPU1_SB_CB<6>")
	)
	(segment
		(start 52.825142 -241.302794)
		(end 51.618642 -241.302794)
		(width 0.18288)
		(layer "In4.Cu")
		(net "M_C_CPU1_SB_CB<6>")
	)
	(segment
		(start 65.193672 -241.071146)
		(end 65.193672 -241.214656)
		(width 0.18288)
		(layer "In4.Cu")
		(net "M_C_CPU1_SB_CB<6>")
	)
	(segment
		(start 67.535044 -240.888012)
		(end 65.926208 -240.888012)
		(width 0.18288)
		(layer "In4.Cu")
		(net "M_C_CPU1_SB_CB<6>")
	)
	(segment
		(start 41.94937 -241.048794)
		(end 41.76649 -240.865914)
		(width 0.18288)
		(layer "In4.Cu")
		(net "M_C_CPU1_SB_CB<6>")
	)
	(segment
		(start 59.558936 -239.995964)
		(end 58.988452 -240.566448)
		(width 0.18288)
		(layer "In4.Cu")
		(net "M_C_CPU1_SB_CB<6>")
	)
	(arc
		(start 86.068154 -242.61318)
		(mid 85.789722 -242.543366)
		(end 85.51291 -242.619276)
		(width 0.088646)
		(layer "In4.Cu")
		(net "M_C_CPU1_SB_CB<6>")
	)
	(arc
		(start 90.292682 -241.796824)
		(mid 90.016207 -241.729504)
		(end 89.74201 -241.80546)
		(width 0.088646)
		(layer "In4.Cu")
		(net "M_C_CPU1_SB_CB<6>")
	)
	(arc
		(start 86.452964 -242.619276)
		(mid 86.265766 -242.669419)
		(end 86.078568 -242.619276)
		(width 0.088646)
		(layer "In4.Cu")
		(net "M_C_CPU1_SB_CB<6>")
	)
	(arc
		(start 92.657168 -240.991644)
		(mid 92.382969 -240.915809)
		(end 92.106496 -240.983008)
		(width 0.088646)
		(layer "In4.Cu")
		(net "M_C_CPU1_SB_CB<6>")
	)
	(arc
		(start 88.4174 -241.799364)
		(mid 88.139222 -241.729641)
		(end 87.862664 -241.80546)
		(width 0.088646)
		(layer "In4.Cu")
		(net "M_C_CPU1_SB_CB<6>")
	)
	(arc
		(start 87.39251 -242.619276)
		(mid 87.205312 -242.669419)
		(end 87.018114 -242.619276)
		(width 0.088646)
		(layer "In4.Cu")
		(net "M_C_CPU1_SB_CB<6>")
	)
	(arc
		(start 91.62161 -241.80546)
		(mid 91.434412 -241.855603)
		(end 91.247214 -241.80546)
		(width 0.088646)
		(layer "In4.Cu")
		(net "M_C_CPU1_SB_CB<6>")
	)
	(arc
		(start 89.352882 -241.796824)
		(mid 89.076407 -241.729504)
		(end 88.80221 -241.80546)
		(width 0.088646)
		(layer "In4.Cu")
		(net "M_C_CPU1_SB_CB<6>")
	)
	(arc
		(start 89.74201 -241.80546)
		(mid 89.554812 -241.855603)
		(end 89.367614 -241.80546)
		(width 0.088646)
		(layer "In4.Cu")
		(net "M_C_CPU1_SB_CB<6>")
	)
	(arc
		(start 85.043264 -243.433346)
		(mid 84.856066 -243.483489)
		(end 84.668868 -243.433346)
		(width 0.088646)
		(layer "In4.Cu")
		(net "M_C_CPU1_SB_CB<6>")
	)
	(arc
		(start 87.0077 -242.61318)
		(mid 86.729522 -242.543488)
		(end 86.452964 -242.619276)
		(width 0.088646)
		(layer "In4.Cu")
		(net "M_C_CPU1_SB_CB<6>")
	)
	(arc
		(start 88.80221 -241.80546)
		(mid 88.615012 -241.855603)
		(end 88.427814 -241.80546)
		(width 0.088646)
		(layer "In4.Cu")
		(net "M_C_CPU1_SB_CB<6>")
	)
	(arc
		(start 91.232482 -241.796824)
		(mid 90.956007 -241.729504)
		(end 90.68181 -241.80546)
		(width 0.088646)
		(layer "In4.Cu")
		(net "M_C_CPU1_SB_CB<6>")
	)
	(arc
		(start 87.580216 -242.294918)
		(mid 87.534212 -242.474855)
		(end 87.407496 -242.61064)
		(width 0.088646)
		(layer "In4.Cu")
		(net "M_C_CPU1_SB_CB<6>")
	)
	(arc
		(start 91.809062 -241.481102)
		(mid 91.761383 -241.664002)
		(end 91.6305 -241.80038)
		(width 0.088646)
		(layer "In4.Cu")
		(net "M_C_CPU1_SB_CB<6>")
	)
	(arc
		(start 90.68181 -241.80546)
		(mid 90.494612 -241.855603)
		(end 90.307414 -241.80546)
		(width 0.088646)
		(layer "In4.Cu")
		(net "M_C_CPU1_SB_CB<6>")
	)
	(arc
		(start 84.103464 -243.433346)
		(mid 84.013192 -243.470945)
		(end 83.916266 -243.483892)
		(width 0.088646)
		(layer "In4.Cu")
		(net "M_C_CPU1_SB_CB<6>")
	)
	(arc
		(start 84.668868 -243.433346)
		(mid 84.394669 -243.357511)
		(end 84.118196 -243.42471)
		(width 0.088646)
		(layer "In4.Cu")
		(net "M_C_CPU1_SB_CB<6>")
	)
	(arc
		(start 85.230716 -243.108988)
		(mid 85.183037 -243.291888)
		(end 85.052154 -243.428266)
		(width 0.088646)
		(layer "In4.Cu")
		(net "M_C_CPU1_SB_CB<6>")
	)
	(arc
		(start 92.935806 -241.41557)
		(mid 92.846718 -241.170585)
		(end 92.657168 -240.991644)
		(width 0.088646)
		(layer "In4.Cu")
		(net "M_C_CPU1_SB_CB<6>")
	)
	(arc
		(start 85.51291 -242.619276)
		(mid 85.311628 -242.816763)
		(end 85.230716 -243.08689)
		(width 0.088646)
		(layer "In4.Cu")
		(net "M_C_CPU1_SB_CB<6>")
	)
	(arc
		(start 92.085668 -240.9952)
		(mid 91.883081 -241.201551)
		(end 91.809062 -241.481102)
		(width 0.088646)
		(layer "In4.Cu")
		(net "M_C_CPU1_SB_CB<6>")
	)
	(arc
		(start 87.856568 -241.809016)
		(mid 87.654155 -242.015429)
		(end 87.580216 -242.294918)
		(width 0.088646)
		(layer "In4.Cu")
		(net "M_C_CPU1_SB_CB<6>")
	)
	(segment
		(start 24.773636 -240.027968)
		(end 25.27808 -240.027968)
		(width 0.20066)
		(layer "F.Cu")
		(net "M_C_CPU1_SB_CB<5>")
	)
	(segment
		(start 26.073862 -239.391698)
		(end 26.2128 -239.391698)
		(width 0.101854)
		(layer "F.Cu")
		(net "M_C_CPU1_SB_CB<5>")
	)
	(segment
		(start 28.707588 -239.391698)
		(end 29.13253 -239.81664)
		(width 0.20066)
		(layer "F.Cu")
		(net "M_C_CPU1_SB_CB<5>")
	)
	(segment
		(start 29.13253 -239.81664)
		(end 30.771846 -239.81664)
		(width 0.20066)
		(layer "F.Cu")
		(net "M_C_CPU1_SB_CB<5>")
	)
	(segment
		(start 25.432512 -239.554258)
		(end 25.595072 -239.391698)
		(width 0.20066)
		(layer "F.Cu")
		(net "M_C_CPU1_SB_CB<5>")
	)
	(segment
		(start 28.590494 -239.391698)
		(end 28.707588 -239.391698)
		(width 0.20066)
		(layer "F.Cu")
		(net "M_C_CPU1_SB_CB<5>")
	)
	(segment
		(start 25.595072 -239.391698)
		(end 26.073862 -239.391698)
		(width 0.20066)
		(layer "F.Cu")
		(net "M_C_CPU1_SB_CB<5>")
	)
	(segment
		(start 28.198318 -239.391698)
		(end 28.590494 -239.391698)
		(width 0.101854)
		(layer "F.Cu")
		(net "M_C_CPU1_SB_CB<5>")
	)
	(segment
		(start 31.876746 -239.81664)
		(end 30.771846 -239.81664)
		(width 0.20066)
		(layer "F.Cu")
		(net "M_C_CPU1_SB_CB<5>")
	)
	(segment
		(start 91.904312 -241.203226)
		(end 91.904566 -241.202972)
		(width 0.20066)
		(layer "F.Cu")
		(net "M_C_CPU1_SB_CB<5>")
	)
	(segment
		(start 91.904566 -241.202972)
		(end 91.904566 -240.667286)
		(width 0.20066)
		(layer "F.Cu")
		(net "M_C_CPU1_SB_CB<5>")
	)
	(segment
		(start 26.2128 -239.391698)
		(end 28.198318 -239.391698)
		(width 0.1016)
		(layer "F.Cu")
		(net "M_C_CPU1_SB_CB<5>")
	)
	(segment
		(start 25.432512 -239.873536)
		(end 25.432512 -239.554258)
		(width 0.20066)
		(layer "F.Cu")
		(net "M_C_CPU1_SB_CB<5>")
	)
	(segment
		(start 24.562308 -239.81664)
		(end 24.773636 -240.027968)
		(width 0.20066)
		(layer "F.Cu")
		(net "M_C_CPU1_SB_CB<5>")
	)
	(segment
		(start 23.228046 -239.81664)
		(end 24.562308 -239.81664)
		(width 0.20066)
		(layer "F.Cu")
		(net "M_C_CPU1_SB_CB<5>")
	)
	(segment
		(start 25.27808 -240.027968)
		(end 25.432512 -239.873536)
		(width 0.20066)
		(layer "F.Cu")
		(net "M_C_CPU1_SB_CB<5>")
	)
	(segment
		(start 83.916012 -242.73383)
		(end 83.574636 -242.73383)
		(width 0.088646)
		(layer "In4.Cu")
		(net "M_C_CPU1_SB_CB<5>")
	)
	(segment
		(start 88.427814 -241.156744)
		(end 88.4174 -241.16284)
		(width 0.088646)
		(layer "In4.Cu")
		(net "M_C_CPU1_SB_CB<5>")
	)
	(segment
		(start 40.54729 -240.076736)
		(end 36.80714 -240.076736)
		(width 0.18288)
		(layer "In4.Cu")
		(net "M_C_CPU1_SB_CB<5>")
	)
	(segment
		(start 40.83558 -240.365026)
		(end 40.54729 -240.076736)
		(width 0.18288)
		(layer "In4.Cu")
		(net "M_C_CPU1_SB_CB<5>")
	)
	(segment
		(start 34.740342 -240.9952)
		(end 34.557462 -240.81232)
		(width 0.18288)
		(layer "In4.Cu")
		(net "M_C_CPU1_SB_CB<5>")
	)
	(segment
		(start 89.748106 -241.160046)
		(end 89.736422 -241.153442)
		(width 0.088646)
		(layer "In4.Cu")
		(net "M_C_CPU1_SB_CB<5>")
	)
	(segment
		(start 33.175702 -240.81232)
		(end 33.175702 -240.424716)
		(width 0.18288)
		(layer "In4.Cu")
		(net "M_C_CPU1_SB_CB<5>")
	)
	(segment
		(start 65.926208 -240.37544)
		(end 65.925954 -240.375694)
		(width 0.18288)
		(layer "In4.Cu")
		(net "M_C_CPU1_SB_CB<5>")
	)
	(segment
		(start 43.823382 -240.365026)
		(end 40.83558 -240.365026)
		(width 0.18288)
		(layer "In4.Cu")
		(net "M_C_CPU1_SB_CB<5>")
	)
	(segment
		(start 91.323414 -241.112802)
		(end 91.247214 -241.156744)
		(width 0.088646)
		(layer "In4.Cu")
		(net "M_C_CPU1_SB_CB<5>")
	)
	(segment
		(start 69.934582 -242.58143)
		(end 67.728592 -240.37544)
		(width 0.18288)
		(layer "In4.Cu")
		(net "M_C_CPU1_SB_CB<5>")
	)
	(segment
		(start 88.808306 -241.160046)
		(end 88.802464 -241.156744)
		(width 0.088646)
		(layer "In4.Cu")
		(net "M_C_CPU1_SB_CB<5>")
	)
	(segment
		(start 35.431222 -240.241836)
		(end 35.248342 -240.424716)
		(width 0.18288)
		(layer "In4.Cu")
		(net "M_C_CPU1_SB_CB<5>")
	)
	(segment
		(start 33.683702 -240.9952)
		(end 33.358582 -240.9952)
		(width 0.18288)
		(layer "In4.Cu")
		(net "M_C_CPU1_SB_CB<5>")
	)
	(segment
		(start 36.64204 -240.241836)
		(end 35.431222 -240.241836)
		(width 0.18288)
		(layer "In4.Cu")
		(net "M_C_CPU1_SB_CB<5>")
	)
	(segment
		(start 51.76139 -240.241836)
		(end 50.231548 -240.241836)
		(width 0.18288)
		(layer "In4.Cu")
		(net "M_C_CPU1_SB_CB<5>")
	)
	(segment
		(start 45.235114 -240.241836)
		(end 43.946572 -240.241836)
		(width 0.18288)
		(layer "In4.Cu")
		(net "M_C_CPU1_SB_CB<5>")
	)
	(segment
		(start 51.875436 -240.12779)
		(end 51.76139 -240.241836)
		(width 0.18288)
		(layer "In4.Cu")
		(net "M_C_CPU1_SB_CB<5>")
	)
	(segment
		(start 34.049462 -240.241836)
		(end 33.866582 -240.424716)
		(width 0.18288)
		(layer "In4.Cu")
		(net "M_C_CPU1_SB_CB<5>")
	)
	(segment
		(start 33.866582 -240.424716)
		(end 33.866582 -240.81232)
		(width 0.18288)
		(layer "In4.Cu")
		(net "M_C_CPU1_SB_CB<5>")
	)
	(segment
		(start 59.252104 -239.482884)
		(end 59.063128 -239.293908)
		(width 0.18288)
		(layer "In4.Cu")
		(net "M_C_CPU1_SB_CB<5>")
	)
	(segment
		(start 61.629544 -240.122456)
		(end 60.989972 -239.482884)
		(width 0.18288)
		(layer "In4.Cu")
		(net "M_C_CPU1_SB_CB<5>")
	)
	(segment
		(start 83.06435 -242.58143)
		(end 69.934582 -242.58143)
		(width 0.18288)
		(layer "In4.Cu")
		(net "M_C_CPU1_SB_CB<5>")
	)
	(segment
		(start 90.687906 -241.160046)
		(end 90.676222 -241.153442)
		(width 0.088646)
		(layer "In4.Cu")
		(net "M_C_CPU1_SB_CB<5>")
	)
	(segment
		(start 43.946572 -240.241836)
		(end 43.823382 -240.365026)
		(width 0.18288)
		(layer "In4.Cu")
		(net "M_C_CPU1_SB_CB<5>")
	)
	(segment
		(start 87.018114 -241.97056)
		(end 87.0077 -241.976656)
		(width 0.088646)
		(layer "In4.Cu")
		(net "M_C_CPU1_SB_CB<5>")
	)
	(segment
		(start 35.248342 -240.81232)
		(end 35.065462 -240.9952)
		(width 0.18288)
		(layer "In4.Cu")
		(net "M_C_CPU1_SB_CB<5>")
	)
	(segment
		(start 86.078568 -241.97056)
		(end 86.068154 -241.976656)
		(width 0.088646)
		(layer "In4.Cu")
		(net "M_C_CPU1_SB_CB<5>")
	)
	(segment
		(start 83.422236 -242.58143)
		(end 83.06435 -242.58143)
		(width 0.088646)
		(layer "In4.Cu")
		(net "M_C_CPU1_SB_CB<5>")
	)
	(segment
		(start 55.876952 -239.293908)
		(end 55.04307 -240.12779)
		(width 0.18288)
		(layer "In4.Cu")
		(net "M_C_CPU1_SB_CB<5>")
	)
	(segment
		(start 32.992822 -240.241836)
		(end 32.301942 -240.241836)
		(width 0.18288)
		(layer "In4.Cu")
		(net "M_C_CPU1_SB_CB<5>")
	)
	(segment
		(start 34.374582 -240.241836)
		(end 34.049462 -240.241836)
		(width 0.18288)
		(layer "In4.Cu")
		(net "M_C_CPU1_SB_CB<5>")
	)
	(segment
		(start 35.248342 -240.424716)
		(end 35.248342 -240.81232)
		(width 0.18288)
		(layer "In4.Cu")
		(net "M_C_CPU1_SB_CB<5>")
	)
	(segment
		(start 55.04307 -240.12779)
		(end 51.875436 -240.12779)
		(width 0.18288)
		(layer "In4.Cu")
		(net "M_C_CPU1_SB_CB<5>")
	)
	(segment
		(start 65.925954 -240.375694)
		(end 63.342774 -240.375694)
		(width 0.18288)
		(layer "In4.Cu")
		(net "M_C_CPU1_SB_CB<5>")
	)
	(segment
		(start 32.301942 -240.241836)
		(end 31.876746 -239.81664)
		(width 0.18288)
		(layer "In4.Cu")
		(net "M_C_CPU1_SB_CB<5>")
	)
	(segment
		(start 87.488268 -241.156744)
		(end 87.479378 -241.161824)
		(width 0.088646)
		(layer "In4.Cu")
		(net "M_C_CPU1_SB_CB<5>")
	)
	(segment
		(start 33.358582 -240.9952)
		(end 33.175702 -240.81232)
		(width 0.18288)
		(layer "In4.Cu")
		(net "M_C_CPU1_SB_CB<5>")
	)
	(segment
		(start 88.802464 -241.156744)
		(end 88.798654 -241.154458)
		(width 0.088646)
		(layer "In4.Cu")
		(net "M_C_CPU1_SB_CB<5>")
	)
	(segment
		(start 34.557462 -240.424716)
		(end 34.374582 -240.241836)
		(width 0.18288)
		(layer "In4.Cu")
		(net "M_C_CPU1_SB_CB<5>")
	)
	(segment
		(start 63.089536 -240.122456)
		(end 61.629544 -240.122456)
		(width 0.18288)
		(layer "In4.Cu")
		(net "M_C_CPU1_SB_CB<5>")
	)
	(segment
		(start 85.138514 -241.97056)
		(end 85.129624 -241.97564)
		(width 0.088646)
		(layer "In4.Cu")
		(net "M_C_CPU1_SB_CB<5>")
	)
	(segment
		(start 33.175702 -240.424716)
		(end 32.992822 -240.241836)
		(width 0.18288)
		(layer "In4.Cu")
		(net "M_C_CPU1_SB_CB<5>")
	)
	(segment
		(start 35.065462 -240.9952)
		(end 34.740342 -240.9952)
		(width 0.18288)
		(layer "In4.Cu")
		(net "M_C_CPU1_SB_CB<5>")
	)
	(segment
		(start 49.383696 -241.089688)
		(end 46.082966 -241.089688)
		(width 0.18288)
		(layer "In4.Cu")
		(net "M_C_CPU1_SB_CB<5>")
	)
	(segment
		(start 67.728592 -240.37544)
		(end 65.926208 -240.37544)
		(width 0.18288)
		(layer "In4.Cu")
		(net "M_C_CPU1_SB_CB<5>")
	)
	(segment
		(start 36.80714 -240.076736)
		(end 36.64204 -240.241836)
		(width 0.18288)
		(layer "In4.Cu")
		(net "M_C_CPU1_SB_CB<5>")
	)
	(segment
		(start 60.989972 -239.482884)
		(end 59.252104 -239.482884)
		(width 0.18288)
		(layer "In4.Cu")
		(net "M_C_CPU1_SB_CB<5>")
	)
	(segment
		(start 50.231548 -240.241836)
		(end 49.383696 -241.089688)
		(width 0.18288)
		(layer "In4.Cu")
		(net "M_C_CPU1_SB_CB<5>")
	)
	(segment
		(start 34.557462 -240.81232)
		(end 34.557462 -240.424716)
		(width 0.18288)
		(layer "In4.Cu")
		(net "M_C_CPU1_SB_CB<5>")
	)
	(segment
		(start 33.866582 -240.81232)
		(end 33.683702 -240.9952)
		(width 0.18288)
		(layer "In4.Cu")
		(net "M_C_CPU1_SB_CB<5>")
	)
	(segment
		(start 87.02421 -241.967004)
		(end 87.018114 -241.97056)
		(width 0.088646)
		(layer "In4.Cu")
		(net "M_C_CPU1_SB_CB<5>")
	)
	(segment
		(start 84.118196 -242.793266)
		(end 84.103464 -242.78463)
		(width 0.088646)
		(layer "In4.Cu")
		(net "M_C_CPU1_SB_CB<5>")
	)
	(segment
		(start 63.342774 -240.375694)
		(end 63.089536 -240.122456)
		(width 0.18288)
		(layer "In4.Cu")
		(net "M_C_CPU1_SB_CB<5>")
	)
	(segment
		(start 83.574636 -242.73383)
		(end 83.422236 -242.58143)
		(width 0.088646)
		(layer "In4.Cu")
		(net "M_C_CPU1_SB_CB<5>")
	)
	(segment
		(start 59.063128 -239.293908)
		(end 55.876952 -239.293908)
		(width 0.18288)
		(layer "In4.Cu")
		(net "M_C_CPU1_SB_CB<5>")
	)
	(segment
		(start 46.082966 -241.089688)
		(end 45.235114 -240.241836)
		(width 0.18288)
		(layer "In4.Cu")
		(net "M_C_CPU1_SB_CB<5>")
	)
	(segment
		(start 84.951062 -242.294918)
		(end 84.951062 -242.317016)
		(width 0.088646)
		(layer "In4.Cu")
		(net "M_C_CPU1_SB_CB<5>")
	)
	(arc
		(start 85.51291 -241.97056)
		(mid 85.325712 -241.920417)
		(end 85.138514 -241.97056)
		(width 0.088646)
		(layer "In4.Cu")
		(net "M_C_CPU1_SB_CB<5>")
	)
	(arc
		(start 90.676222 -241.153442)
		(mid 90.491367 -241.106492)
		(end 90.307414 -241.156744)
		(width 0.088646)
		(layer "In4.Cu")
		(net "M_C_CPU1_SB_CB<5>")
	)
	(arc
		(start 91.247214 -241.156744)
		(mid 90.968011 -241.232384)
		(end 90.687906 -241.160046)
		(width 0.088646)
		(layer "In4.Cu")
		(net "M_C_CPU1_SB_CB<5>")
	)
	(arc
		(start 90.307414 -241.156744)
		(mid 90.028211 -241.232384)
		(end 89.748106 -241.160046)
		(width 0.088646)
		(layer "In4.Cu")
		(net "M_C_CPU1_SB_CB<5>")
	)
	(arc
		(start 84.668868 -242.78463)
		(mid 84.394639 -242.860555)
		(end 84.118196 -242.793266)
		(width 0.088646)
		(layer "In4.Cu")
		(net "M_C_CPU1_SB_CB<5>")
	)
	(arc
		(start 85.129624 -241.97564)
		(mid 84.99871 -242.112)
		(end 84.951062 -242.294918)
		(width 0.088646)
		(layer "In4.Cu")
		(net "M_C_CPU1_SB_CB<5>")
	)
	(arc
		(start 87.862664 -241.156744)
		(mid 87.675466 -241.106601)
		(end 87.488268 -241.156744)
		(width 0.088646)
		(layer "In4.Cu")
		(net "M_C_CPU1_SB_CB<5>")
	)
	(arc
		(start 91.904566 -240.667286)
		(mid 91.628663 -240.909185)
		(end 91.323414 -241.112802)
		(width 0.088646)
		(layer "In4.Cu")
		(net "M_C_CPU1_SB_CB<5>")
	)
	(arc
		(start 89.736422 -241.153442)
		(mid 89.551567 -241.106492)
		(end 89.367614 -241.156744)
		(width 0.088646)
		(layer "In4.Cu")
		(net "M_C_CPU1_SB_CB<5>")
	)
	(arc
		(start 84.103464 -242.78463)
		(mid 84.013085 -242.746875)
		(end 83.916012 -242.73383)
		(width 0.088646)
		(layer "In4.Cu")
		(net "M_C_CPU1_SB_CB<5>")
	)
	(arc
		(start 87.300816 -241.481102)
		(mid 87.226825 -241.760668)
		(end 87.02421 -241.967004)
		(width 0.088646)
		(layer "In4.Cu")
		(net "M_C_CPU1_SB_CB<5>")
	)
	(arc
		(start 87.0077 -241.976656)
		(mid 86.729522 -242.046379)
		(end 86.452964 -241.97056)
		(width 0.088646)
		(layer "In4.Cu")
		(net "M_C_CPU1_SB_CB<5>")
	)
	(arc
		(start 89.367614 -241.156744)
		(mid 89.088411 -241.232384)
		(end 88.808306 -241.160046)
		(width 0.088646)
		(layer "In4.Cu")
		(net "M_C_CPU1_SB_CB<5>")
	)
	(arc
		(start 86.452964 -241.97056)
		(mid 86.265766 -241.920417)
		(end 86.078568 -241.97056)
		(width 0.088646)
		(layer "In4.Cu")
		(net "M_C_CPU1_SB_CB<5>")
	)
	(arc
		(start 87.479378 -241.161824)
		(mid 87.348464 -241.298184)
		(end 87.300816 -241.481102)
		(width 0.088646)
		(layer "In4.Cu")
		(net "M_C_CPU1_SB_CB<5>")
	)
	(arc
		(start 88.4174 -241.16284)
		(mid 88.139222 -241.232563)
		(end 87.862664 -241.156744)
		(width 0.088646)
		(layer "In4.Cu")
		(net "M_C_CPU1_SB_CB<5>")
	)
	(arc
		(start 84.951062 -242.317016)
		(mid 84.870151 -242.587144)
		(end 84.668868 -242.78463)
		(width 0.088646)
		(layer "In4.Cu")
		(net "M_C_CPU1_SB_CB<5>")
	)
	(arc
		(start 86.068154 -241.976656)
		(mid 85.789722 -242.046502)
		(end 85.51291 -241.97056)
		(width 0.088646)
		(layer "In4.Cu")
		(net "M_C_CPU1_SB_CB<5>")
	)
	(arc
		(start 88.798654 -241.154458)
		(mid 88.612935 -241.106506)
		(end 88.427814 -241.156744)
		(width 0.088646)
		(layer "In4.Cu")
		(net "M_C_CPU1_SB_CB<5>")
	)
	(segment
		(start 24.562308 -241.516662)
		(end 24.801068 -241.755422)
		(width 0.20066)
		(layer "F.Cu")
		(net "M_C_CPU1_SB_CB<4>")
	)
	(segment
		(start 28.977844 -241.09172)
		(end 29.402786 -241.516662)
		(width 0.20066)
		(layer "F.Cu")
		(net "M_C_CPU1_SB_CB<4>")
	)
	(segment
		(start 28.598622 -241.09172)
		(end 28.977844 -241.09172)
		(width 0.20066)
		(layer "F.Cu")
		(net "M_C_CPU1_SB_CB<4>")
	)
	(segment
		(start 26.459942 -241.09172)
		(end 28.529026 -241.09172)
		(width 0.1016)
		(layer "F.Cu")
		(net "M_C_CPU1_SB_CB<4>")
	)
	(segment
		(start 26.069798 -241.09172)
		(end 26.459942 -241.09172)
		(width 0.101854)
		(layer "F.Cu")
		(net "M_C_CPU1_SB_CB<4>")
	)
	(segment
		(start 25.432512 -241.582702)
		(end 25.432512 -241.293142)
		(width 0.20066)
		(layer "F.Cu")
		(net "M_C_CPU1_SB_CB<4>")
	)
	(segment
		(start 25.259792 -241.755422)
		(end 25.432512 -241.582702)
		(width 0.20066)
		(layer "F.Cu")
		(net "M_C_CPU1_SB_CB<4>")
	)
	(segment
		(start 25.432512 -241.293142)
		(end 25.633934 -241.09172)
		(width 0.20066)
		(layer "F.Cu")
		(net "M_C_CPU1_SB_CB<4>")
	)
	(segment
		(start 29.402786 -241.516662)
		(end 30.771846 -241.516662)
		(width 0.20066)
		(layer "F.Cu")
		(net "M_C_CPU1_SB_CB<4>")
	)
	(segment
		(start 24.801068 -241.755422)
		(end 25.259792 -241.755422)
		(width 0.20066)
		(layer "F.Cu")
		(net "M_C_CPU1_SB_CB<4>")
	)
	(segment
		(start 25.633934 -241.09172)
		(end 26.069798 -241.09172)
		(width 0.20066)
		(layer "F.Cu")
		(net "M_C_CPU1_SB_CB<4>")
	)
	(segment
		(start 92.374212 -242.016788)
		(end 92.374212 -241.481102)
		(width 0.20066)
		(layer "F.Cu")
		(net "M_C_CPU1_SB_CB<4>")
	)
	(segment
		(start 28.529026 -241.09172)
		(end 28.598622 -241.09172)
		(width 0.101854)
		(layer "F.Cu")
		(net "M_C_CPU1_SB_CB<4>")
	)
	(segment
		(start 31.876746 -241.516662)
		(end 30.771846 -241.516662)
		(width 0.20066)
		(layer "F.Cu")
		(net "M_C_CPU1_SB_CB<4>")
	)
	(segment
		(start 23.228046 -241.516662)
		(end 24.562308 -241.516662)
		(width 0.20066)
		(layer "F.Cu")
		(net "M_C_CPU1_SB_CB<4>")
	)
	(segment
		(start 92.374466 -242.017042)
		(end 92.374212 -242.016788)
		(width 0.20066)
		(layer "F.Cu")
		(net "M_C_CPU1_SB_CB<4>")
	)
	(segment
		(start 33.474152 -241.941858)
		(end 32.301942 -241.941858)
		(width 0.18288)
		(layer "In4.Cu")
		(net "M_C_CPU1_SB_CB<4>")
	)
	(segment
		(start 89.287096 -241.979196)
		(end 89.272364 -241.97056)
		(width 0.088646)
		(layer "In4.Cu")
		(net "M_C_CPU1_SB_CB<4>")
	)
	(segment
		(start 85.14461 -243.59489)
		(end 85.138514 -243.598446)
		(width 0.088646)
		(layer "In4.Cu")
		(net "M_C_CPU1_SB_CB<4>")
	)
	(segment
		(start 33.634172 -242.472972)
		(end 33.634172 -242.101878)
		(width 0.18288)
		(layer "In4.Cu")
		(net "M_C_CPU1_SB_CB<4>")
	)
	(segment
		(start 90.226896 -241.979196)
		(end 90.212164 -241.97056)
		(width 0.088646)
		(layer "In4.Cu")
		(net "M_C_CPU1_SB_CB<4>")
	)
	(segment
		(start 44.990258 -241.941858)
		(end 44.04487 -241.941858)
		(width 0.18288)
		(layer "In4.Cu")
		(net "M_C_CPU1_SB_CB<4>")
	)
	(segment
		(start 92.374212 -241.481102)
		(end 92.686886 -241.481102)
		(width 0.088646)
		(layer "In4.Cu")
		(net "M_C_CPU1_SB_CB<4>")
	)
	(segment
		(start 83.58378 -243.674138)
		(end 83.486752 -243.57711)
		(width 0.088646)
		(layer "In4.Cu")
		(net "M_C_CPU1_SB_CB<4>")
	)
	(segment
		(start 34.487612 -241.941858)
		(end 34.327592 -242.101878)
		(width 0.18288)
		(layer "In4.Cu")
		(net "M_C_CPU1_SB_CB<4>")
	)
	(segment
		(start 85.608668 -242.78463)
		(end 85.599778 -242.78971)
		(width 0.088646)
		(layer "In4.Cu")
		(net "M_C_CPU1_SB_CB<4>")
	)
	(segment
		(start 91.166696 -241.979196)
		(end 91.151964 -241.97056)
		(width 0.088646)
		(layer "In4.Cu")
		(net "M_C_CPU1_SB_CB<4>")
	)
	(segment
		(start 63.10122 -241.940842)
		(end 63.099696 -241.942366)
		(width 0.18288)
		(layer "In4.Cu")
		(net "M_C_CPU1_SB_CB<4>")
	)
	(segment
		(start 45.493432 -242.445032)
		(end 44.990258 -241.941858)
		(width 0.18288)
		(layer "In4.Cu")
		(net "M_C_CPU1_SB_CB<4>")
	)
	(segment
		(start 42.71645 -242.373658)
		(end 40.354504 -242.373658)
		(width 0.18288)
		(layer "In4.Cu")
		(net "M_C_CPU1_SB_CB<4>")
	)
	(segment
		(start 43.14825 -241.941858)
		(end 42.71645 -242.373658)
		(width 0.18288)
		(layer "In4.Cu")
		(net "M_C_CPU1_SB_CB<4>")
	)
	(segment
		(start 46.420532 -242.445032)
		(end 45.493432 -242.445032)
		(width 0.18288)
		(layer "In4.Cu")
		(net "M_C_CPU1_SB_CB<4>")
	)
	(segment
		(start 83.91652 -243.674138)
		(end 83.58378 -243.674138)
		(width 0.088646)
		(layer "In4.Cu")
		(net "M_C_CPU1_SB_CB<4>")
	)
	(segment
		(start 63.238634 -241.941858)
		(end 63.237618 -241.940842)
		(width 0.18288)
		(layer "In4.Cu")
		(net "M_C_CPU1_SB_CB<4>")
	)
	(segment
		(start 34.327592 -242.472972)
		(end 34.167572 -242.632992)
		(width 0.18288)
		(layer "In4.Cu")
		(net "M_C_CPU1_SB_CB<4>")
	)
	(segment
		(start 60.67425 -241.942366)
		(end 59.825636 -241.093752)
		(width 0.18288)
		(layer "In4.Cu")
		(net "M_C_CPU1_SB_CB<4>")
	)
	(segment
		(start 87.958168 -241.97056)
		(end 87.958422 -241.97056)
		(width 0.088646)
		(layer "In4.Cu")
		(net "M_C_CPU1_SB_CB<4>")
	)
	(segment
		(start 46.767242 -242.791742)
		(end 46.420532 -242.445032)
		(width 0.18288)
		(layer "In4.Cu")
		(net "M_C_CPU1_SB_CB<4>")
	)
	(segment
		(start 69.49313 -243.57711)
		(end 67.857878 -241.941858)
		(width 0.18288)
		(layer "In4.Cu")
		(net "M_C_CPU1_SB_CB<4>")
	)
	(segment
		(start 44.044362 -241.942366)
		(end 43.148758 -241.942366)
		(width 0.18288)
		(layer "In4.Cu")
		(net "M_C_CPU1_SB_CB<4>")
	)
	(segment
		(start 34.167572 -242.632992)
		(end 33.794192 -242.632992)
		(width 0.18288)
		(layer "In4.Cu")
		(net "M_C_CPU1_SB_CB<4>")
	)
	(segment
		(start 87.958422 -241.97056)
		(end 87.943436 -241.979196)
		(width 0.088646)
		(layer "In4.Cu")
		(net "M_C_CPU1_SB_CB<4>")
	)
	(segment
		(start 85.138514 -243.598446)
		(end 85.123782 -243.607082)
		(width 0.088646)
		(layer "In4.Cu")
		(net "M_C_CPU1_SB_CB<4>")
	)
	(segment
		(start 34.327592 -242.101878)
		(end 34.327592 -242.472972)
		(width 0.18288)
		(layer "In4.Cu")
		(net "M_C_CPU1_SB_CB<4>")
	)
	(segment
		(start 59.825636 -241.093752)
		(end 56.171084 -241.093752)
		(width 0.18288)
		(layer "In4.Cu")
		(net "M_C_CPU1_SB_CB<4>")
	)
	(segment
		(start 86.937596 -242.793266)
		(end 86.922864 -242.78463)
		(width 0.088646)
		(layer "In4.Cu")
		(net "M_C_CPU1_SB_CB<4>")
	)
	(segment
		(start 44.04487 -241.941858)
		(end 44.044362 -241.942366)
		(width 0.18288)
		(layer "In4.Cu")
		(net "M_C_CPU1_SB_CB<4>")
	)
	(segment
		(start 87.770716 -242.294918)
		(end 87.770716 -242.309142)
		(width 0.088646)
		(layer "In4.Cu")
		(net "M_C_CPU1_SB_CB<4>")
	)
	(segment
		(start 50.461926 -241.941858)
		(end 49.953672 -242.450112)
		(width 0.18288)
		(layer "In4.Cu")
		(net "M_C_CPU1_SB_CB<4>")
	)
	(segment
		(start 40.354504 -242.373658)
		(end 39.922704 -241.941858)
		(width 0.18288)
		(layer "In4.Cu")
		(net "M_C_CPU1_SB_CB<4>")
	)
	(segment
		(start 39.922704 -241.941858)
		(end 34.487612 -241.941858)
		(width 0.18288)
		(layer "In4.Cu")
		(net "M_C_CPU1_SB_CB<4>")
	)
	(segment
		(start 92.686886 -241.481102)
		(end 92.74429 -241.423698)
		(width 0.088646)
		(layer "In4.Cu")
		(net "M_C_CPU1_SB_CB<4>")
	)
	(segment
		(start 92.5703 -241.161824)
		(end 92.56141 -241.156744)
		(width 0.088646)
		(layer "In4.Cu")
		(net "M_C_CPU1_SB_CB<4>")
	)
	(segment
		(start 91.999562 -241.481102)
		(end 91.999562 -241.496596)
		(width 0.088646)
		(layer "In4.Cu")
		(net "M_C_CPU1_SB_CB<4>")
	)
	(segment
		(start 47.226982 -242.791742)
		(end 46.767242 -242.791742)
		(width 0.18288)
		(layer "In4.Cu")
		(net "M_C_CPU1_SB_CB<4>")
	)
	(segment
		(start 47.568612 -242.450112)
		(end 47.226982 -242.791742)
		(width 0.18288)
		(layer "In4.Cu")
		(net "M_C_CPU1_SB_CB<4>")
	)
	(segment
		(start 43.148758 -241.942366)
		(end 43.14825 -241.941858)
		(width 0.18288)
		(layer "In4.Cu")
		(net "M_C_CPU1_SB_CB<4>")
	)
	(segment
		(start 49.953672 -242.450112)
		(end 47.568612 -242.450112)
		(width 0.18288)
		(layer "In4.Cu")
		(net "M_C_CPU1_SB_CB<4>")
	)
	(segment
		(start 83.486752 -243.57711)
		(end 83.06435 -243.57711)
		(width 0.088646)
		(layer "In4.Cu")
		(net "M_C_CPU1_SB_CB<4>")
	)
	(segment
		(start 88.347296 -241.979196)
		(end 88.332564 -241.97056)
		(width 0.088646)
		(layer "In4.Cu")
		(net "M_C_CPU1_SB_CB<4>")
	)
	(segment
		(start 33.794192 -242.632992)
		(end 33.634172 -242.472972)
		(width 0.18288)
		(layer "In4.Cu")
		(net "M_C_CPU1_SB_CB<4>")
	)
	(segment
		(start 92.187014 -241.156744)
		(end 92.178124 -241.161824)
		(width 0.088646)
		(layer "In4.Cu")
		(net "M_C_CPU1_SB_CB<4>")
	)
	(segment
		(start 67.857878 -241.941858)
		(end 63.238634 -241.941858)
		(width 0.18288)
		(layer "In4.Cu")
		(net "M_C_CPU1_SB_CB<4>")
	)
	(segment
		(start 56.171084 -241.093752)
		(end 54.123844 -241.941858)
		(width 0.18288)
		(layer "In4.Cu")
		(net "M_C_CPU1_SB_CB<4>")
	)
	(segment
		(start 32.301942 -241.941858)
		(end 31.876746 -241.516662)
		(width 0.18288)
		(layer "In4.Cu")
		(net "M_C_CPU1_SB_CB<4>")
	)
	(segment
		(start 33.634172 -242.101878)
		(end 33.474152 -241.941858)
		(width 0.18288)
		(layer "In4.Cu")
		(net "M_C_CPU1_SB_CB<4>")
	)
	(segment
		(start 83.06435 -243.57711)
		(end 69.49313 -243.57711)
		(width 0.18288)
		(layer "In4.Cu")
		(net "M_C_CPU1_SB_CB<4>")
	)
	(segment
		(start 54.123844 -241.941858)
		(end 50.461926 -241.941858)
		(width 0.18288)
		(layer "In4.Cu")
		(net "M_C_CPU1_SB_CB<4>")
	)
	(segment
		(start 63.237618 -241.940842)
		(end 63.10122 -241.940842)
		(width 0.18288)
		(layer "In4.Cu")
		(net "M_C_CPU1_SB_CB<4>")
	)
	(segment
		(start 63.099696 -241.942366)
		(end 60.67425 -241.942366)
		(width 0.18288)
		(layer "In4.Cu")
		(net "M_C_CPU1_SB_CB<4>")
	)
	(arc
		(start 83.952842 -243.673122)
		(mid 83.934689 -243.673925)
		(end 83.91652 -243.674138)
		(width 0.088646)
		(layer "In4.Cu")
		(net "M_C_CPU1_SB_CB<4>")
	)
	(arc
		(start 87.943436 -241.979196)
		(mid 87.816713 -242.114977)
		(end 87.770716 -242.294918)
		(width 0.088646)
		(layer "In4.Cu")
		(net "M_C_CPU1_SB_CB<4>")
	)
	(arc
		(start 88.897968 -241.97056)
		(mid 88.623769 -242.046395)
		(end 88.347296 -241.979196)
		(width 0.088646)
		(layer "In4.Cu")
		(net "M_C_CPU1_SB_CB<4>")
	)
	(arc
		(start 92.178124 -241.161824)
		(mid 92.04721 -241.298184)
		(end 91.999562 -241.481102)
		(width 0.088646)
		(layer "In4.Cu")
		(net "M_C_CPU1_SB_CB<4>")
	)
	(arc
		(start 90.212164 -241.97056)
		(mid 90.024966 -241.920417)
		(end 89.837768 -241.97056)
		(width 0.088646)
		(layer "In4.Cu")
		(net "M_C_CPU1_SB_CB<4>")
	)
	(arc
		(start 86.548468 -242.78463)
		(mid 86.265766 -242.860372)
		(end 85.983064 -242.78463)
		(width 0.088646)
		(layer "In4.Cu")
		(net "M_C_CPU1_SB_CB<4>")
	)
	(arc
		(start 85.123782 -243.607082)
		(mid 84.847307 -243.674402)
		(end 84.57311 -243.598446)
		(width 0.088646)
		(layer "In4.Cu")
		(net "M_C_CPU1_SB_CB<4>")
	)
	(arc
		(start 91.999562 -241.496596)
		(mid 91.920192 -241.77033)
		(end 91.717368 -241.97056)
		(width 0.088646)
		(layer "In4.Cu")
		(net "M_C_CPU1_SB_CB<4>")
	)
	(arc
		(start 89.837768 -241.97056)
		(mid 89.563569 -242.046395)
		(end 89.287096 -241.979196)
		(width 0.088646)
		(layer "In4.Cu")
		(net "M_C_CPU1_SB_CB<4>")
	)
	(arc
		(start 91.717368 -241.97056)
		(mid 91.443169 -242.046395)
		(end 91.166696 -241.979196)
		(width 0.088646)
		(layer "In4.Cu")
		(net "M_C_CPU1_SB_CB<4>")
	)
	(arc
		(start 85.421216 -243.108988)
		(mid 85.347225 -243.388554)
		(end 85.14461 -243.59489)
		(width 0.088646)
		(layer "In4.Cu")
		(net "M_C_CPU1_SB_CB<4>")
	)
	(arc
		(start 88.332564 -241.97056)
		(mid 88.145366 -241.920417)
		(end 87.958168 -241.97056)
		(width 0.088646)
		(layer "In4.Cu")
		(net "M_C_CPU1_SB_CB<4>")
	)
	(arc
		(start 91.151964 -241.97056)
		(mid 90.964766 -241.920417)
		(end 90.777568 -241.97056)
		(width 0.088646)
		(layer "In4.Cu")
		(net "M_C_CPU1_SB_CB<4>")
	)
	(arc
		(start 92.74429 -241.423698)
		(mid 92.686134 -241.273585)
		(end 92.5703 -241.161824)
		(width 0.088646)
		(layer "In4.Cu")
		(net "M_C_CPU1_SB_CB<4>")
	)
	(arc
		(start 84.57311 -243.598446)
		(mid 84.385912 -243.548303)
		(end 84.198714 -243.598446)
		(width 0.088646)
		(layer "In4.Cu")
		(net "M_C_CPU1_SB_CB<4>")
	)
	(arc
		(start 86.922864 -242.78463)
		(mid 86.735666 -242.734487)
		(end 86.548468 -242.78463)
		(width 0.088646)
		(layer "In4.Cu")
		(net "M_C_CPU1_SB_CB<4>")
	)
	(arc
		(start 87.770716 -242.309142)
		(mid 87.691575 -242.583765)
		(end 87.488268 -242.78463)
		(width 0.088646)
		(layer "In4.Cu")
		(net "M_C_CPU1_SB_CB<4>")
	)
	(arc
		(start 90.777568 -241.97056)
		(mid 90.503369 -242.046395)
		(end 90.226896 -241.979196)
		(width 0.088646)
		(layer "In4.Cu")
		(net "M_C_CPU1_SB_CB<4>")
	)
	(arc
		(start 85.599778 -242.78971)
		(mid 85.468864 -242.92607)
		(end 85.421216 -243.108988)
		(width 0.088646)
		(layer "In4.Cu")
		(net "M_C_CPU1_SB_CB<4>")
	)
	(arc
		(start 87.488268 -242.78463)
		(mid 87.214039 -242.860555)
		(end 86.937596 -242.793266)
		(width 0.088646)
		(layer "In4.Cu")
		(net "M_C_CPU1_SB_CB<4>")
	)
	(arc
		(start 92.56141 -241.156744)
		(mid 92.374212 -241.106601)
		(end 92.187014 -241.156744)
		(width 0.088646)
		(layer "In4.Cu")
		(net "M_C_CPU1_SB_CB<4>")
	)
	(arc
		(start 84.198714 -243.598446)
		(mid 84.080083 -243.649966)
		(end 83.952842 -243.673122)
		(width 0.088646)
		(layer "In4.Cu")
		(net "M_C_CPU1_SB_CB<4>")
	)
	(arc
		(start 85.983064 -242.78463)
		(mid 85.795866 -242.734487)
		(end 85.608668 -242.78463)
		(width 0.088646)
		(layer "In4.Cu")
		(net "M_C_CPU1_SB_CB<4>")
	)
	(arc
		(start 89.272364 -241.97056)
		(mid 89.085166 -241.920417)
		(end 88.897968 -241.97056)
		(width 0.088646)
		(layer "In4.Cu")
		(net "M_C_CPU1_SB_CB<4>")
	)
	(segment
		(start 33.828228 -233.14279)
		(end 33.954212 -233.016806)
		(width 0.20066)
		(layer "F.Cu")
		(net "M_C_CPU1_SB_CB<3>")
	)
	(segment
		(start 32.037274 -233.441748)
		(end 32.51708 -233.441748)
		(width 0.20066)
		(layer "F.Cu")
		(net "M_C_CPU1_SB_CB<3>")
	)
	(segment
		(start 33.14446 -232.916222)
		(end 33.371028 -233.14279)
		(width 0.20066)
		(layer "F.Cu")
		(net "M_C_CPU1_SB_CB<3>")
	)
	(segment
		(start 29.899864 -233.441748)
		(end 31.972758 -233.441748)
		(width 0.1016)
		(layer "F.Cu")
		(net "M_C_CPU1_SB_CB<3>")
	)
	(segment
		(start 29.151326 -233.14279)
		(end 29.151326 -233.299254)
		(width 0.20066)
		(layer "F.Cu")
		(net "M_C_CPU1_SB_CB<3>")
	)
	(segment
		(start 33.371028 -233.14279)
		(end 33.828228 -233.14279)
		(width 0.20066)
		(layer "F.Cu")
		(net "M_C_CPU1_SB_CB<3>")
	)
	(segment
		(start 32.51708 -233.441748)
		(end 32.666178 -233.29265)
		(width 0.20066)
		(layer "F.Cu")
		(net "M_C_CPU1_SB_CB<3>")
	)
	(segment
		(start 32.860488 -232.916222)
		(end 33.14446 -232.916222)
		(width 0.20066)
		(layer "F.Cu")
		(net "M_C_CPU1_SB_CB<3>")
	)
	(segment
		(start 29.516578 -233.441748)
		(end 29.899864 -233.441748)
		(width 0.101854)
		(layer "F.Cu")
		(net "M_C_CPU1_SB_CB<3>")
	)
	(segment
		(start 93.314266 -238.761524)
		(end 93.314012 -238.76127)
		(width 0.20066)
		(layer "F.Cu")
		(net "M_C_CPU1_SB_CB<3>")
	)
	(segment
		(start 27.328114 -233.016806)
		(end 29.025342 -233.016806)
		(width 0.20066)
		(layer "F.Cu")
		(net "M_C_CPU1_SB_CB<3>")
	)
	(segment
		(start 29.025342 -233.016806)
		(end 29.151326 -233.14279)
		(width 0.20066)
		(layer "F.Cu")
		(net "M_C_CPU1_SB_CB<3>")
	)
	(segment
		(start 29.29382 -233.441748)
		(end 29.516578 -233.441748)
		(width 0.20066)
		(layer "F.Cu")
		(net "M_C_CPU1_SB_CB<3>")
	)
	(segment
		(start 31.972758 -233.441748)
		(end 32.037274 -233.441748)
		(width 0.101854)
		(layer "F.Cu")
		(net "M_C_CPU1_SB_CB<3>")
	)
	(segment
		(start 32.666178 -233.29265)
		(end 32.666178 -233.110532)
		(width 0.20066)
		(layer "F.Cu")
		(net "M_C_CPU1_SB_CB<3>")
	)
	(segment
		(start 33.954212 -233.016806)
		(end 34.871914 -233.016806)
		(width 0.20066)
		(layer "F.Cu")
		(net "M_C_CPU1_SB_CB<3>")
	)
	(segment
		(start 29.151326 -233.299254)
		(end 29.29382 -233.441748)
		(width 0.20066)
		(layer "F.Cu")
		(net "M_C_CPU1_SB_CB<3>")
	)
	(segment
		(start 35.976814 -233.016806)
		(end 34.871914 -233.016806)
		(width 0.20066)
		(layer "F.Cu")
		(net "M_C_CPU1_SB_CB<3>")
	)
	(segment
		(start 93.314012 -238.76127)
		(end 93.314012 -238.225584)
		(width 0.20066)
		(layer "F.Cu")
		(net "M_C_CPU1_SB_CB<3>")
	)
	(segment
		(start 32.666178 -233.110532)
		(end 32.860488 -232.916222)
		(width 0.20066)
		(layer "F.Cu")
		(net "M_C_CPU1_SB_CB<3>")
	)
	(segment
		(start 39.862252 -231.832658)
		(end 39.862252 -232.408984)
		(width 0.18288)
		(layer "In4.Cu")
		(net "M_C_CPU1_SB_CB<3>")
	)
	(segment
		(start 87.4014 -237.730792)
		(end 87.39251 -237.736126)
		(width 0.088646)
		(layer "In4.Cu")
		(net "M_C_CPU1_SB_CB<3>")
	)
	(segment
		(start 85.230716 -238.21009)
		(end 85.230716 -238.225584)
		(width 0.088646)
		(layer "In4.Cu")
		(net "M_C_CPU1_SB_CB<3>")
	)
	(segment
		(start 89.843356 -237.739428)
		(end 89.837514 -237.736126)
		(width 0.088646)
		(layer "In4.Cu")
		(net "M_C_CPU1_SB_CB<3>")
	)
	(segment
		(start 85.052154 -238.544862)
		(end 85.043264 -238.549942)
		(width 0.088646)
		(layer "In4.Cu")
		(net "M_C_CPU1_SB_CB<3>")
	)
	(segment
		(start 61.971682 -232.591864)
		(end 61.858144 -232.638854)
		(width 0.18288)
		(layer "In4.Cu")
		(net "M_C_CPU1_SB_CB<3>")
	)
	(segment
		(start 40.736012 -232.591864)
		(end 40.553132 -232.408984)
		(width 0.18288)
		(layer "In4.Cu")
		(net "M_C_CPU1_SB_CB<3>")
	)
	(segment
		(start 84.002372 -238.433102)
		(end 83.958684 -238.47679)
		(width 0.088646)
		(layer "In4.Cu")
		(net "M_C_CPU1_SB_CB<3>")
	)
	(segment
		(start 38.689026 -232.591864)
		(end 38.506146 -232.408984)
		(width 0.18288)
		(layer "In4.Cu")
		(net "M_C_CPU1_SB_CB<3>")
	)
	(segment
		(start 60.040012 -232.591864)
		(end 53.33111 -232.591864)
		(width 0.18288)
		(layer "In4.Cu")
		(net "M_C_CPU1_SB_CB<3>")
	)
	(segment
		(start 91.717114 -237.736126)
		(end 91.711272 -237.73257)
		(width 0.088646)
		(layer "In4.Cu")
		(net "M_C_CPU1_SB_CB<3>")
	)
	(segment
		(start 61.498988 -232.960672)
		(end 60.40882 -232.960672)
		(width 0.18288)
		(layer "In4.Cu")
		(net "M_C_CPU1_SB_CB<3>")
	)
	(segment
		(start 37.998146 -230.708708)
		(end 37.815266 -230.891588)
		(width 0.18288)
		(layer "In4.Cu")
		(net "M_C_CPU1_SB_CB<3>")
	)
	(segment
		(start 84.552028 -238.433102)
		(end 84.002372 -238.433102)
		(width 0.088646)
		(layer "In4.Cu")
		(net "M_C_CPU1_SB_CB<3>")
	)
	(segment
		(start 38.506146 -230.891588)
		(end 38.323266 -230.708708)
		(width 0.18288)
		(layer "In4.Cu")
		(net "M_C_CPU1_SB_CB<3>")
	)
	(segment
		(start 40.370252 -231.649778)
		(end 40.045132 -231.649778)
		(width 0.18288)
		(layer "In4.Cu")
		(net "M_C_CPU1_SB_CB<3>")
	)
	(segment
		(start 86.078568 -237.736126)
		(end 86.068154 -237.73003)
		(width 0.088646)
		(layer "In4.Cu")
		(net "M_C_CPU1_SB_CB<3>")
	)
	(segment
		(start 40.553132 -232.408984)
		(end 40.553132 -231.832658)
		(width 0.18288)
		(layer "In4.Cu")
		(net "M_C_CPU1_SB_CB<3>")
	)
	(segment
		(start 62.736476 -233.103928)
		(end 62.224412 -232.591864)
		(width 0.18288)
		(layer "In4.Cu")
		(net "M_C_CPU1_SB_CB<3>")
	)
	(segment
		(start 37.815266 -230.891588)
		(end 37.815266 -232.408984)
		(width 0.18288)
		(layer "In4.Cu")
		(net "M_C_CPU1_SB_CB<3>")
	)
	(segment
		(start 93.048836 -237.960408)
		(end 92.873576 -237.960408)
		(width 0.088646)
		(layer "In4.Cu")
		(net "M_C_CPU1_SB_CB<3>")
	)
	(segment
		(start 49.640998 -232.591864)
		(end 40.736012 -232.591864)
		(width 0.18288)
		(layer "In4.Cu")
		(net "M_C_CPU1_SB_CB<3>")
	)
	(segment
		(start 72.033638 -238.47679)
		(end 67.934332 -234.377484)
		(width 0.18288)
		(layer "In4.Cu")
		(net "M_C_CPU1_SB_CB<3>")
	)
	(segment
		(start 38.323266 -230.708708)
		(end 37.998146 -230.708708)
		(width 0.18288)
		(layer "In4.Cu")
		(net "M_C_CPU1_SB_CB<3>")
	)
	(segment
		(start 67.934332 -234.377484)
		(end 65.44818 -234.377484)
		(width 0.18288)
		(layer "In4.Cu")
		(net "M_C_CPU1_SB_CB<3>")
	)
	(segment
		(start 50.491136 -231.741726)
		(end 49.640998 -232.591864)
		(width 0.18288)
		(layer "In4.Cu")
		(net "M_C_CPU1_SB_CB<3>")
	)
	(segment
		(start 83.064096 -238.47679)
		(end 72.033638 -238.47679)
		(width 0.18288)
		(layer "In4.Cu")
		(net "M_C_CPU1_SB_CB<3>")
	)
	(segment
		(start 40.045132 -231.649778)
		(end 39.862252 -231.832658)
		(width 0.18288)
		(layer "In4.Cu")
		(net "M_C_CPU1_SB_CB<3>")
	)
	(segment
		(start 65.44818 -234.377484)
		(end 64.174624 -233.103928)
		(width 0.18288)
		(layer "In4.Cu")
		(net "M_C_CPU1_SB_CB<3>")
	)
	(segment
		(start 90.777314 -237.736126)
		(end 90.771472 -237.73257)
		(width 0.088646)
		(layer "In4.Cu")
		(net "M_C_CPU1_SB_CB<3>")
	)
	(segment
		(start 60.40882 -232.960672)
		(end 60.040012 -232.591864)
		(width 0.18288)
		(layer "In4.Cu")
		(net "M_C_CPU1_SB_CB<3>")
	)
	(segment
		(start 84.668868 -238.549942)
		(end 84.552028 -238.433102)
		(width 0.088646)
		(layer "In4.Cu")
		(net "M_C_CPU1_SB_CB<3>")
	)
	(segment
		(start 64.174624 -233.103928)
		(end 62.736476 -233.103928)
		(width 0.18288)
		(layer "In4.Cu")
		(net "M_C_CPU1_SB_CB<3>")
	)
	(segment
		(start 40.553132 -231.832658)
		(end 40.370252 -231.649778)
		(width 0.18288)
		(layer "In4.Cu")
		(net "M_C_CPU1_SB_CB<3>")
	)
	(segment
		(start 39.862252 -232.408984)
		(end 39.679372 -232.591864)
		(width 0.18288)
		(layer "In4.Cu")
		(net "M_C_CPU1_SB_CB<3>")
	)
	(segment
		(start 88.897714 -237.736126)
		(end 88.893142 -237.733332)
		(width 0.088646)
		(layer "In4.Cu")
		(net "M_C_CPU1_SB_CB<3>")
	)
	(segment
		(start 38.506146 -232.408984)
		(end 38.506146 -230.891588)
		(width 0.18288)
		(layer "In4.Cu")
		(net "M_C_CPU1_SB_CB<3>")
	)
	(segment
		(start 62.224412 -232.591864)
		(end 61.971682 -232.591864)
		(width 0.18288)
		(layer "In4.Cu")
		(net "M_C_CPU1_SB_CB<3>")
	)
	(segment
		(start 87.957914 -237.736126)
		(end 87.958168 -237.735872)
		(width 0.088646)
		(layer "In4.Cu")
		(net "M_C_CPU1_SB_CB<3>")
	)
	(segment
		(start 52.480972 -231.741726)
		(end 50.491136 -231.741726)
		(width 0.18288)
		(layer "In4.Cu")
		(net "M_C_CPU1_SB_CB<3>")
	)
	(segment
		(start 88.903556 -237.739428)
		(end 88.897714 -237.736126)
		(width 0.088646)
		(layer "In4.Cu")
		(net "M_C_CPU1_SB_CB<3>")
	)
	(segment
		(start 83.958684 -238.47679)
		(end 83.064096 -238.47679)
		(width 0.088646)
		(layer "In4.Cu")
		(net "M_C_CPU1_SB_CB<3>")
	)
	(segment
		(start 39.679372 -232.591864)
		(end 38.689026 -232.591864)
		(width 0.18288)
		(layer "In4.Cu")
		(net "M_C_CPU1_SB_CB<3>")
	)
	(segment
		(start 53.33111 -232.591864)
		(end 52.480972 -231.741726)
		(width 0.18288)
		(layer "In4.Cu")
		(net "M_C_CPU1_SB_CB<3>")
	)
	(segment
		(start 91.722956 -237.739428)
		(end 91.717114 -237.736126)
		(width 0.088646)
		(layer "In4.Cu")
		(net "M_C_CPU1_SB_CB<3>")
	)
	(segment
		(start 37.815266 -232.408984)
		(end 37.632386 -232.591864)
		(width 0.18288)
		(layer "In4.Cu")
		(net "M_C_CPU1_SB_CB<3>")
	)
	(segment
		(start 87.018114 -237.736126)
		(end 87.0077 -237.73003)
		(width 0.088646)
		(layer "In4.Cu")
		(net "M_C_CPU1_SB_CB<3>")
	)
	(segment
		(start 36.401756 -232.591864)
		(end 35.976814 -233.016806)
		(width 0.18288)
		(layer "In4.Cu")
		(net "M_C_CPU1_SB_CB<3>")
	)
	(segment
		(start 93.314012 -238.225584)
		(end 93.048836 -237.960408)
		(width 0.088646)
		(layer "In4.Cu")
		(net "M_C_CPU1_SB_CB<3>")
	)
	(segment
		(start 61.79439 -232.66527)
		(end 61.498988 -232.960672)
		(width 0.18288)
		(layer "In4.Cu")
		(net "M_C_CPU1_SB_CB<3>")
	)
	(segment
		(start 61.858144 -232.638854)
		(end 61.79439 -232.66527)
		(width 0.18288)
		(layer "In4.Cu")
		(net "M_C_CPU1_SB_CB<3>")
	)
	(segment
		(start 90.783156 -237.739428)
		(end 90.777314 -237.736126)
		(width 0.088646)
		(layer "In4.Cu")
		(net "M_C_CPU1_SB_CB<3>")
	)
	(segment
		(start 37.632386 -232.591864)
		(end 36.401756 -232.591864)
		(width 0.18288)
		(layer "In4.Cu")
		(net "M_C_CPU1_SB_CB<3>")
	)
	(segment
		(start 89.837514 -237.736126)
		(end 89.831672 -237.73257)
		(width 0.088646)
		(layer "In4.Cu")
		(net "M_C_CPU1_SB_CB<3>")
	)
	(arc
		(start 86.068154 -237.73003)
		(mid 85.789722 -237.660184)
		(end 85.51291 -237.736126)
		(width 0.088646)
		(layer "In4.Cu")
		(net "M_C_CPU1_SB_CB<3>")
	)
	(arc
		(start 85.043264 -238.549942)
		(mid 84.856066 -238.600085)
		(end 84.668868 -238.549942)
		(width 0.088646)
		(layer "In4.Cu")
		(net "M_C_CPU1_SB_CB<3>")
	)
	(arc
		(start 91.151964 -237.736126)
		(mid 90.96801 -237.786255)
		(end 90.783156 -237.739428)
		(width 0.088646)
		(layer "In4.Cu")
		(net "M_C_CPU1_SB_CB<3>")
	)
	(arc
		(start 87.0077 -237.73003)
		(mid 86.729522 -237.660307)
		(end 86.452964 -237.736126)
		(width 0.088646)
		(layer "In4.Cu")
		(net "M_C_CPU1_SB_CB<3>")
	)
	(arc
		(start 88.332564 -237.736126)
		(mid 88.145256 -237.786235)
		(end 87.957914 -237.736126)
		(width 0.088646)
		(layer "In4.Cu")
		(net "M_C_CPU1_SB_CB<3>")
	)
	(arc
		(start 86.452964 -237.736126)
		(mid 86.265766 -237.786269)
		(end 86.078568 -237.736126)
		(width 0.088646)
		(layer "In4.Cu")
		(net "M_C_CPU1_SB_CB<3>")
	)
	(arc
		(start 87.958168 -237.735872)
		(mid 87.680442 -237.660027)
		(end 87.4014 -237.730792)
		(width 0.088646)
		(layer "In4.Cu")
		(net "M_C_CPU1_SB_CB<3>")
	)
	(arc
		(start 88.893142 -237.733332)
		(mid 88.612478 -237.660324)
		(end 88.332564 -237.736126)
		(width 0.088646)
		(layer "In4.Cu")
		(net "M_C_CPU1_SB_CB<3>")
	)
	(arc
		(start 85.230716 -238.225584)
		(mid 85.183037 -238.408484)
		(end 85.052154 -238.544862)
		(width 0.088646)
		(layer "In4.Cu")
		(net "M_C_CPU1_SB_CB<3>")
	)
	(arc
		(start 92.091764 -237.736126)
		(mid 91.90781 -237.786255)
		(end 91.722956 -237.739428)
		(width 0.088646)
		(layer "In4.Cu")
		(net "M_C_CPU1_SB_CB<3>")
	)
	(arc
		(start 85.51291 -237.736126)
		(mid 85.310087 -237.936357)
		(end 85.230716 -238.21009)
		(width 0.088646)
		(layer "In4.Cu")
		(net "M_C_CPU1_SB_CB<3>")
	)
	(arc
		(start 90.771472 -237.73257)
		(mid 90.491337 -237.660287)
		(end 90.212164 -237.736126)
		(width 0.088646)
		(layer "In4.Cu")
		(net "M_C_CPU1_SB_CB<3>")
	)
	(arc
		(start 91.711272 -237.73257)
		(mid 91.431137 -237.660287)
		(end 91.151964 -237.736126)
		(width 0.088646)
		(layer "In4.Cu")
		(net "M_C_CPU1_SB_CB<3>")
	)
	(arc
		(start 89.272364 -237.736126)
		(mid 89.08841 -237.786255)
		(end 88.903556 -237.739428)
		(width 0.088646)
		(layer "In4.Cu")
		(net "M_C_CPU1_SB_CB<3>")
	)
	(arc
		(start 90.212164 -237.736126)
		(mid 90.02821 -237.786255)
		(end 89.843356 -237.739428)
		(width 0.088646)
		(layer "In4.Cu")
		(net "M_C_CPU1_SB_CB<3>")
	)
	(arc
		(start 92.873576 -237.960408)
		(mid 92.530291 -237.682309)
		(end 92.091764 -237.736126)
		(width 0.088646)
		(layer "In4.Cu")
		(net "M_C_CPU1_SB_CB<3>")
	)
	(arc
		(start 87.39251 -237.736126)
		(mid 87.205312 -237.786269)
		(end 87.018114 -237.736126)
		(width 0.088646)
		(layer "In4.Cu")
		(net "M_C_CPU1_SB_CB<3>")
	)
	(arc
		(start 89.831672 -237.73257)
		(mid 89.551537 -237.660287)
		(end 89.272364 -237.736126)
		(width 0.088646)
		(layer "In4.Cu")
		(net "M_C_CPU1_SB_CB<3>")
	)
	(segment
		(start 28.475178 -234.716574)
		(end 28.90012 -234.291632)
		(width 0.20066)
		(layer "F.Cu")
		(net "M_C_CPU1_SB_CB<2>")
	)
	(segment
		(start 29.50845 -234.291632)
		(end 29.912818 -234.291632)
		(width 0.101854)
		(layer "F.Cu")
		(net "M_C_CPU1_SB_CB<2>")
	)
	(segment
		(start 33.345374 -234.92841)
		(end 33.55721 -234.716574)
		(width 0.20066)
		(layer "F.Cu")
		(net "M_C_CPU1_SB_CB<2>")
	)
	(segment
		(start 32.045402 -234.291632)
		(end 32.605726 -234.291632)
		(width 0.20066)
		(layer "F.Cu")
		(net "M_C_CPU1_SB_CB<2>")
	)
	(segment
		(start 32.74949 -234.761024)
		(end 32.916876 -234.92841)
		(width 0.20066)
		(layer "F.Cu")
		(net "M_C_CPU1_SB_CB<2>")
	)
	(segment
		(start 31.972758 -234.291632)
		(end 32.045402 -234.291632)
		(width 0.101854)
		(layer "F.Cu")
		(net "M_C_CPU1_SB_CB<2>")
	)
	(segment
		(start 28.90012 -234.291632)
		(end 29.50845 -234.291632)
		(width 0.20066)
		(layer "F.Cu")
		(net "M_C_CPU1_SB_CB<2>")
	)
	(segment
		(start 93.784166 -239.575086)
		(end 93.784166 -239.0394)
		(width 0.20066)
		(layer "F.Cu")
		(net "M_C_CPU1_SB_CB<2>")
	)
	(segment
		(start 27.328114 -234.716574)
		(end 28.475178 -234.716574)
		(width 0.20066)
		(layer "F.Cu")
		(net "M_C_CPU1_SB_CB<2>")
	)
	(segment
		(start 93.783912 -239.57534)
		(end 93.784166 -239.575086)
		(width 0.20066)
		(layer "F.Cu")
		(net "M_C_CPU1_SB_CB<2>")
	)
	(segment
		(start 33.55721 -234.716574)
		(end 34.871914 -234.716574)
		(width 0.20066)
		(layer "F.Cu")
		(net "M_C_CPU1_SB_CB<2>")
	)
	(segment
		(start 35.976814 -234.716574)
		(end 34.871914 -234.716574)
		(width 0.20066)
		(layer "F.Cu")
		(net "M_C_CPU1_SB_CB<2>")
	)
	(segment
		(start 32.916876 -234.92841)
		(end 33.345374 -234.92841)
		(width 0.20066)
		(layer "F.Cu")
		(net "M_C_CPU1_SB_CB<2>")
	)
	(segment
		(start 29.912818 -234.291632)
		(end 31.972758 -234.291632)
		(width 0.1016)
		(layer "F.Cu")
		(net "M_C_CPU1_SB_CB<2>")
	)
	(segment
		(start 32.605726 -234.291632)
		(end 32.74949 -234.435396)
		(width 0.20066)
		(layer "F.Cu")
		(net "M_C_CPU1_SB_CB<2>")
	)
	(segment
		(start 32.74949 -234.435396)
		(end 32.74949 -234.761024)
		(width 0.20066)
		(layer "F.Cu")
		(net "M_C_CPU1_SB_CB<2>")
	)
	(segment
		(start 43.98264 -234.54868)
		(end 42.83964 -234.54868)
		(width 0.18288)
		(layer "In4.Cu")
		(net "M_C_CPU1_SB_CB<2>")
	)
	(segment
		(start 45.378878 -234.291632)
		(end 45.033438 -233.946192)
		(width 0.18288)
		(layer "In4.Cu")
		(net "M_C_CPU1_SB_CB<2>")
	)
	(segment
		(start 64.22898 -235.010452)
		(end 63.45936 -235.010452)
		(width 0.18288)
		(layer "In4.Cu")
		(net "M_C_CPU1_SB_CB<2>")
	)
	(segment
		(start 42.83964 -234.54868)
		(end 42.65676 -234.3658)
		(width 0.18288)
		(layer "In4.Cu")
		(net "M_C_CPU1_SB_CB<2>")
	)
	(segment
		(start 88.80983 -238.545624)
		(end 88.802464 -238.549942)
		(width 0.088646)
		(layer "In4.Cu")
		(net "M_C_CPU1_SB_CB<2>")
	)
	(segment
		(start 60.713366 -234.563158)
		(end 60.397898 -234.24769)
		(width 0.18288)
		(layer "In4.Cu")
		(net "M_C_CPU1_SB_CB<2>")
	)
	(segment
		(start 93.206824 -238.59617)
		(end 93.126814 -238.549942)
		(width 0.088646)
		(layer "In4.Cu")
		(net "M_C_CPU1_SB_CB<2>")
	)
	(segment
		(start 57.084976 -234.02925)
		(end 57.084976 -234.299252)
		(width 0.18288)
		(layer "In4.Cu")
		(net "M_C_CPU1_SB_CB<2>")
	)
	(segment
		(start 53.37937 -234.206796)
		(end 52.614322 -233.441748)
		(width 0.18288)
		(layer "In4.Cu")
		(net "M_C_CPU1_SB_CB<2>")
	)
	(segment
		(start 42.65676 -234.122468)
		(end 42.47388 -233.939588)
		(width 0.18288)
		(layer "In4.Cu")
		(net "M_C_CPU1_SB_CB<2>")
	)
	(segment
		(start 57.775856 -234.02925)
		(end 57.592976 -233.84637)
		(width 0.18288)
		(layer "In4.Cu")
		(net "M_C_CPU1_SB_CB<2>")
	)
	(segment
		(start 57.267856 -233.84637)
		(end 57.084976 -234.02925)
		(width 0.18288)
		(layer "In4.Cu")
		(net "M_C_CPU1_SB_CB<2>")
	)
	(segment
		(start 61.383926 -234.24769)
		(end 61.068458 -234.563158)
		(width 0.18288)
		(layer "In4.Cu")
		(net "M_C_CPU1_SB_CB<2>")
	)
	(segment
		(start 38.059106 -235.081064)
		(end 38.059106 -234.291124)
		(width 0.18288)
		(layer "In4.Cu")
		(net "M_C_CPU1_SB_CB<2>")
	)
	(segment
		(start 41.96588 -234.122468)
		(end 41.96588 -234.3658)
		(width 0.18288)
		(layer "In4.Cu")
		(net "M_C_CPU1_SB_CB<2>")
	)
	(segment
		(start 84.386166 -239.414304)
		(end 83.950556 -239.414304)
		(width 0.088646)
		(layer "In4.Cu")
		(net "M_C_CPU1_SB_CB<2>")
	)
	(segment
		(start 59.175396 -234.482132)
		(end 57.958736 -234.482132)
		(width 0.18288)
		(layer "In4.Cu")
		(net "M_C_CPU1_SB_CB<2>")
	)
	(segment
		(start 54.992524 -234.206796)
		(end 53.37937 -234.206796)
		(width 0.18288)
		(layer "In4.Cu")
		(net "M_C_CPU1_SB_CB<2>")
	)
	(segment
		(start 57.775856 -234.299252)
		(end 57.775856 -234.02925)
		(width 0.18288)
		(layer "In4.Cu")
		(net "M_C_CPU1_SB_CB<2>")
	)
	(segment
		(start 50.441606 -233.441748)
		(end 49.591722 -234.291632)
		(width 0.18288)
		(layer "In4.Cu")
		(net "M_C_CPU1_SB_CB<2>")
	)
	(segment
		(start 38.749986 -234.291124)
		(end 38.749986 -235.089446)
		(width 0.18288)
		(layer "In4.Cu")
		(net "M_C_CPU1_SB_CB<2>")
	)
	(segment
		(start 56.902096 -234.482132)
		(end 55.26786 -234.482132)
		(width 0.18288)
		(layer "In4.Cu")
		(net "M_C_CPU1_SB_CB<2>")
	)
	(segment
		(start 60.397898 -234.24769)
		(end 59.409838 -234.24769)
		(width 0.18288)
		(layer "In4.Cu")
		(net "M_C_CPU1_SB_CB<2>")
	)
	(segment
		(start 38.932866 -234.108244)
		(end 38.749986 -234.291124)
		(width 0.18288)
		(layer "In4.Cu")
		(net "M_C_CPU1_SB_CB<2>")
	)
	(segment
		(start 88.427814 -238.549942)
		(end 88.4174 -238.543846)
		(width 0.088646)
		(layer "In4.Cu")
		(net "M_C_CPU1_SB_CB<2>")
	)
	(segment
		(start 41.783 -234.54868)
		(end 40.140128 -234.54868)
		(width 0.18288)
		(layer "In4.Cu")
		(net "M_C_CPU1_SB_CB<2>")
	)
	(segment
		(start 61.068458 -234.563158)
		(end 60.713366 -234.563158)
		(width 0.18288)
		(layer "In4.Cu")
		(net "M_C_CPU1_SB_CB<2>")
	)
	(segment
		(start 89.742264 -238.549942)
		(end 89.737692 -238.552736)
		(width 0.088646)
		(layer "In4.Cu")
		(net "M_C_CPU1_SB_CB<2>")
	)
	(segment
		(start 44.585128 -233.946192)
		(end 43.98264 -234.54868)
		(width 0.18288)
		(layer "In4.Cu")
		(net "M_C_CPU1_SB_CB<2>")
	)
	(segment
		(start 90.68943 -238.545624)
		(end 90.682064 -238.549942)
		(width 0.088646)
		(layer "In4.Cu")
		(net "M_C_CPU1_SB_CB<2>")
	)
	(segment
		(start 65.2907 -236.072172)
		(end 64.22898 -235.010452)
		(width 0.18288)
		(layer "In4.Cu")
		(net "M_C_CPU1_SB_CB<2>")
	)
	(segment
		(start 42.14876 -233.939588)
		(end 41.96588 -234.122468)
		(width 0.18288)
		(layer "In4.Cu")
		(net "M_C_CPU1_SB_CB<2>")
	)
	(segment
		(start 85.522054 -239.358678)
		(end 85.513164 -239.363758)
		(width 0.088646)
		(layer "In4.Cu")
		(net "M_C_CPU1_SB_CB<2>")
	)
	(segment
		(start 45.033438 -233.946192)
		(end 44.585128 -233.946192)
		(width 0.18288)
		(layer "In4.Cu")
		(net "M_C_CPU1_SB_CB<2>")
	)
	(segment
		(start 40.140128 -234.54868)
		(end 39.699692 -234.108244)
		(width 0.18288)
		(layer "In4.Cu")
		(net "M_C_CPU1_SB_CB<2>")
	)
	(segment
		(start 37.876226 -234.108244)
		(end 36.585144 -234.108244)
		(width 0.18288)
		(layer "In4.Cu")
		(net "M_C_CPU1_SB_CB<2>")
	)
	(segment
		(start 83.064096 -239.47247)
		(end 71.600568 -239.47247)
		(width 0.18288)
		(layer "In4.Cu")
		(net "M_C_CPU1_SB_CB<2>")
	)
	(segment
		(start 91.621864 -238.549942)
		(end 91.617292 -238.552736)
		(width 0.088646)
		(layer "In4.Cu")
		(net "M_C_CPU1_SB_CB<2>")
	)
	(segment
		(start 92.56903 -238.545624)
		(end 92.561664 -238.549942)
		(width 0.088646)
		(layer "In4.Cu")
		(net "M_C_CPU1_SB_CB<2>")
	)
	(segment
		(start 57.958736 -234.482132)
		(end 57.775856 -234.299252)
		(width 0.18288)
		(layer "In4.Cu")
		(net "M_C_CPU1_SB_CB<2>")
	)
	(segment
		(start 85.700616 -239.029494)
		(end 85.700616 -239.0394)
		(width 0.088646)
		(layer "In4.Cu")
		(net "M_C_CPU1_SB_CB<2>")
	)
	(segment
		(start 55.26786 -234.482132)
		(end 54.992524 -234.206796)
		(width 0.18288)
		(layer "In4.Cu")
		(net "M_C_CPU1_SB_CB<2>")
	)
	(segment
		(start 88.802464 -238.549942)
		(end 88.798654 -238.552228)
		(width 0.088646)
		(layer "In4.Cu")
		(net "M_C_CPU1_SB_CB<2>")
	)
	(segment
		(start 52.614322 -233.441748)
		(end 50.441606 -233.441748)
		(width 0.18288)
		(layer "In4.Cu")
		(net "M_C_CPU1_SB_CB<2>")
	)
	(segment
		(start 68.20027 -236.072172)
		(end 65.2907 -236.072172)
		(width 0.18288)
		(layer "In4.Cu")
		(net "M_C_CPU1_SB_CB<2>")
	)
	(segment
		(start 83.89239 -239.47247)
		(end 83.064096 -239.47247)
		(width 0.088646)
		(layer "In4.Cu")
		(net "M_C_CPU1_SB_CB<2>")
	)
	(segment
		(start 59.409838 -234.24769)
		(end 59.175396 -234.482132)
		(width 0.18288)
		(layer "In4.Cu")
		(net "M_C_CPU1_SB_CB<2>")
	)
	(segment
		(start 38.059106 -234.291124)
		(end 37.876226 -234.108244)
		(width 0.18288)
		(layer "In4.Cu")
		(net "M_C_CPU1_SB_CB<2>")
	)
	(segment
		(start 41.96588 -234.3658)
		(end 41.783 -234.54868)
		(width 0.18288)
		(layer "In4.Cu")
		(net "M_C_CPU1_SB_CB<2>")
	)
	(segment
		(start 42.47388 -233.939588)
		(end 42.14876 -233.939588)
		(width 0.18288)
		(layer "In4.Cu")
		(net "M_C_CPU1_SB_CB<2>")
	)
	(segment
		(start 71.600568 -239.47247)
		(end 68.20027 -236.072172)
		(width 0.18288)
		(layer "In4.Cu")
		(net "M_C_CPU1_SB_CB<2>")
	)
	(segment
		(start 89.74963 -238.545624)
		(end 89.742264 -238.549942)
		(width 0.088646)
		(layer "In4.Cu")
		(net "M_C_CPU1_SB_CB<2>")
	)
	(segment
		(start 91.62923 -238.545624)
		(end 91.621864 -238.549942)
		(width 0.088646)
		(layer "In4.Cu")
		(net "M_C_CPU1_SB_CB<2>")
	)
	(segment
		(start 84.588096 -239.355122)
		(end 84.573364 -239.363758)
		(width 0.088646)
		(layer "In4.Cu")
		(net "M_C_CPU1_SB_CB<2>")
	)
	(segment
		(start 63.45936 -235.010452)
		(end 62.696598 -234.24769)
		(width 0.18288)
		(layer "In4.Cu")
		(net "M_C_CPU1_SB_CB<2>")
	)
	(segment
		(start 90.682064 -238.549942)
		(end 90.677492 -238.552736)
		(width 0.088646)
		(layer "In4.Cu")
		(net "M_C_CPU1_SB_CB<2>")
	)
	(segment
		(start 57.084976 -234.299252)
		(end 56.902096 -234.482132)
		(width 0.18288)
		(layer "In4.Cu")
		(net "M_C_CPU1_SB_CB<2>")
	)
	(segment
		(start 62.696598 -234.24769)
		(end 61.383926 -234.24769)
		(width 0.18288)
		(layer "In4.Cu")
		(net "M_C_CPU1_SB_CB<2>")
	)
	(segment
		(start 49.591722 -234.291632)
		(end 45.378878 -234.291632)
		(width 0.18288)
		(layer "In4.Cu")
		(net "M_C_CPU1_SB_CB<2>")
	)
	(segment
		(start 38.567106 -235.272326)
		(end 38.250368 -235.272326)
		(width 0.18288)
		(layer "In4.Cu")
		(net "M_C_CPU1_SB_CB<2>")
	)
	(segment
		(start 38.250368 -235.272326)
		(end 38.059106 -235.081064)
		(width 0.18288)
		(layer "In4.Cu")
		(net "M_C_CPU1_SB_CB<2>")
	)
	(segment
		(start 39.699692 -234.108244)
		(end 38.932866 -234.108244)
		(width 0.18288)
		(layer "In4.Cu")
		(net "M_C_CPU1_SB_CB<2>")
	)
	(segment
		(start 42.65676 -234.3658)
		(end 42.65676 -234.122468)
		(width 0.18288)
		(layer "In4.Cu")
		(net "M_C_CPU1_SB_CB<2>")
	)
	(segment
		(start 92.561664 -238.549942)
		(end 92.557092 -238.552736)
		(width 0.088646)
		(layer "In4.Cu")
		(net "M_C_CPU1_SB_CB<2>")
	)
	(segment
		(start 83.950556 -239.414304)
		(end 83.89239 -239.47247)
		(width 0.088646)
		(layer "In4.Cu")
		(net "M_C_CPU1_SB_CB<2>")
	)
	(segment
		(start 57.592976 -233.84637)
		(end 57.267856 -233.84637)
		(width 0.18288)
		(layer "In4.Cu")
		(net "M_C_CPU1_SB_CB<2>")
	)
	(segment
		(start 36.585144 -234.108244)
		(end 35.976814 -234.716574)
		(width 0.18288)
		(layer "In4.Cu")
		(net "M_C_CPU1_SB_CB<2>")
	)
	(segment
		(start 38.749986 -235.089446)
		(end 38.567106 -235.272326)
		(width 0.18288)
		(layer "In4.Cu")
		(net "M_C_CPU1_SB_CB<2>")
	)
	(arc
		(start 86.922864 -238.549942)
		(mid 86.735666 -238.600085)
		(end 86.548468 -238.549942)
		(width 0.088646)
		(layer "In4.Cu")
		(net "M_C_CPU1_SB_CB<2>")
	)
	(arc
		(start 92.187014 -238.549942)
		(mid 91.908691 -238.474183)
		(end 91.62923 -238.545624)
		(width 0.088646)
		(layer "In4.Cu")
		(net "M_C_CPU1_SB_CB<2>")
	)
	(arc
		(start 87.862664 -238.549942)
		(mid 87.675466 -238.600085)
		(end 87.488268 -238.549942)
		(width 0.088646)
		(layer "In4.Cu")
		(net "M_C_CPU1_SB_CB<2>")
	)
	(arc
		(start 91.617292 -238.552736)
		(mid 91.431878 -238.600248)
		(end 91.247214 -238.549942)
		(width 0.088646)
		(layer "In4.Cu")
		(net "M_C_CPU1_SB_CB<2>")
	)
	(arc
		(start 85.700616 -239.0394)
		(mid 85.652937 -239.2223)
		(end 85.522054 -239.358678)
		(width 0.088646)
		(layer "In4.Cu")
		(net "M_C_CPU1_SB_CB<2>")
	)
	(arc
		(start 93.784166 -239.0394)
		(mid 93.509994 -238.798899)
		(end 93.206824 -238.59617)
		(width 0.088646)
		(layer "In4.Cu")
		(net "M_C_CPU1_SB_CB<2>")
	)
	(arc
		(start 93.126814 -238.549942)
		(mid 92.848491 -238.474183)
		(end 92.56903 -238.545624)
		(width 0.088646)
		(layer "In4.Cu")
		(net "M_C_CPU1_SB_CB<2>")
	)
	(arc
		(start 90.307414 -238.549942)
		(mid 90.029091 -238.474183)
		(end 89.74963 -238.545624)
		(width 0.088646)
		(layer "In4.Cu")
		(net "M_C_CPU1_SB_CB<2>")
	)
	(arc
		(start 92.557092 -238.552736)
		(mid 92.371678 -238.600248)
		(end 92.187014 -238.549942)
		(width 0.088646)
		(layer "In4.Cu")
		(net "M_C_CPU1_SB_CB<2>")
	)
	(arc
		(start 89.367614 -238.549942)
		(mid 89.089291 -238.474183)
		(end 88.80983 -238.545624)
		(width 0.088646)
		(layer "In4.Cu")
		(net "M_C_CPU1_SB_CB<2>")
	)
	(arc
		(start 85.983064 -238.549942)
		(mid 85.778729 -238.752547)
		(end 85.700616 -239.029494)
		(width 0.088646)
		(layer "In4.Cu")
		(net "M_C_CPU1_SB_CB<2>")
	)
	(arc
		(start 85.513164 -239.363758)
		(mid 85.325966 -239.413901)
		(end 85.138768 -239.363758)
		(width 0.088646)
		(layer "In4.Cu")
		(net "M_C_CPU1_SB_CB<2>")
	)
	(arc
		(start 88.4174 -238.543846)
		(mid 88.139222 -238.474123)
		(end 87.862664 -238.549942)
		(width 0.088646)
		(layer "In4.Cu")
		(net "M_C_CPU1_SB_CB<2>")
	)
	(arc
		(start 88.798654 -238.552228)
		(mid 88.612935 -238.60018)
		(end 88.427814 -238.549942)
		(width 0.088646)
		(layer "In4.Cu")
		(net "M_C_CPU1_SB_CB<2>")
	)
	(arc
		(start 84.573364 -239.363758)
		(mid 84.483092 -239.401357)
		(end 84.386166 -239.414304)
		(width 0.088646)
		(layer "In4.Cu")
		(net "M_C_CPU1_SB_CB<2>")
	)
	(arc
		(start 91.247214 -238.549942)
		(mid 90.968891 -238.474183)
		(end 90.68943 -238.545624)
		(width 0.088646)
		(layer "In4.Cu")
		(net "M_C_CPU1_SB_CB<2>")
	)
	(arc
		(start 89.737692 -238.552736)
		(mid 89.552278 -238.600248)
		(end 89.367614 -238.549942)
		(width 0.088646)
		(layer "In4.Cu")
		(net "M_C_CPU1_SB_CB<2>")
	)
	(arc
		(start 86.548468 -238.549942)
		(mid 86.265766 -238.474166)
		(end 85.983064 -238.549942)
		(width 0.088646)
		(layer "In4.Cu")
		(net "M_C_CPU1_SB_CB<2>")
	)
	(arc
		(start 87.488268 -238.549942)
		(mid 87.205566 -238.474166)
		(end 86.922864 -238.549942)
		(width 0.088646)
		(layer "In4.Cu")
		(net "M_C_CPU1_SB_CB<2>")
	)
	(arc
		(start 90.677492 -238.552736)
		(mid 90.492078 -238.600248)
		(end 90.307414 -238.549942)
		(width 0.088646)
		(layer "In4.Cu")
		(net "M_C_CPU1_SB_CB<2>")
	)
	(arc
		(start 85.138768 -239.363758)
		(mid 84.864569 -239.287923)
		(end 84.588096 -239.355122)
		(width 0.088646)
		(layer "In4.Cu")
		(net "M_C_CPU1_SB_CB<2>")
	)
	(segment
		(start 24.562308 -233.86669)
		(end 24.773636 -234.078018)
		(width 0.20066)
		(layer "F.Cu")
		(net "M_C_CPU1_SB_CB<1>")
	)
	(segment
		(start 25.27808 -234.078018)
		(end 25.432512 -233.923586)
		(width 0.20066)
		(layer "F.Cu")
		(net "M_C_CPU1_SB_CB<1>")
	)
	(segment
		(start 26.2128 -233.441748)
		(end 28.198318 -233.441748)
		(width 0.1016)
		(layer "F.Cu")
		(net "M_C_CPU1_SB_CB<1>")
	)
	(segment
		(start 92.374466 -238.761524)
		(end 92.374212 -238.76127)
		(width 0.20066)
		(layer "F.Cu")
		(net "M_C_CPU1_SB_CB<1>")
	)
	(segment
		(start 25.595072 -233.441748)
		(end 26.065734 -233.441748)
		(width 0.20066)
		(layer "F.Cu")
		(net "M_C_CPU1_SB_CB<1>")
	)
	(segment
		(start 25.432512 -233.604308)
		(end 25.595072 -233.441748)
		(width 0.20066)
		(layer "F.Cu")
		(net "M_C_CPU1_SB_CB<1>")
	)
	(segment
		(start 29.13253 -233.86669)
		(end 30.771846 -233.86669)
		(width 0.20066)
		(layer "F.Cu")
		(net "M_C_CPU1_SB_CB<1>")
	)
	(segment
		(start 28.198318 -233.441748)
		(end 28.590494 -233.441748)
		(width 0.101854)
		(layer "F.Cu")
		(net "M_C_CPU1_SB_CB<1>")
	)
	(segment
		(start 25.432512 -233.923586)
		(end 25.432512 -233.604308)
		(width 0.20066)
		(layer "F.Cu")
		(net "M_C_CPU1_SB_CB<1>")
	)
	(segment
		(start 24.773636 -234.078018)
		(end 25.27808 -234.078018)
		(width 0.20066)
		(layer "F.Cu")
		(net "M_C_CPU1_SB_CB<1>")
	)
	(segment
		(start 92.374212 -238.76127)
		(end 92.374212 -238.225584)
		(width 0.20066)
		(layer "F.Cu")
		(net "M_C_CPU1_SB_CB<1>")
	)
	(segment
		(start 28.707588 -233.441748)
		(end 29.13253 -233.86669)
		(width 0.20066)
		(layer "F.Cu")
		(net "M_C_CPU1_SB_CB<1>")
	)
	(segment
		(start 23.228046 -233.86669)
		(end 24.562308 -233.86669)
		(width 0.20066)
		(layer "F.Cu")
		(net "M_C_CPU1_SB_CB<1>")
	)
	(segment
		(start 31.876746 -233.86669)
		(end 30.771846 -233.86669)
		(width 0.20066)
		(layer "F.Cu")
		(net "M_C_CPU1_SB_CB<1>")
	)
	(segment
		(start 28.590494 -233.441748)
		(end 28.707588 -233.441748)
		(width 0.20066)
		(layer "F.Cu")
		(net "M_C_CPU1_SB_CB<1>")
	)
	(segment
		(start 26.065734 -233.441748)
		(end 26.2128 -233.441748)
		(width 0.101854)
		(layer "F.Cu")
		(net "M_C_CPU1_SB_CB<1>")
	)
	(segment
		(start 86.937596 -237.909862)
		(end 86.922864 -237.901226)
		(width 0.088646)
		(layer "In4.Cu")
		(net "M_C_CPU1_SB_CB<1>")
	)
	(segment
		(start 85.421216 -238.225584)
		(end 85.421216 -238.23549)
		(width 0.088646)
		(layer "In4.Cu")
		(net "M_C_CPU1_SB_CB<1>")
	)
	(segment
		(start 84.12099 -238.774478)
		(end 83.920838 -238.97463)
		(width 0.088646)
		(layer "In4.Cu")
		(net "M_C_CPU1_SB_CB<1>")
	)
	(segment
		(start 91.621864 -237.900972)
		(end 91.616022 -237.89767)
		(width 0.088646)
		(layer "In4.Cu")
		(net "M_C_CPU1_SB_CB<1>")
	)
	(segment
		(start 34.278062 -233.258868)
		(end 34.278062 -232.858056)
		(width 0.18288)
		(layer "In4.Cu")
		(net "M_C_CPU1_SB_CB<1>")
	)
	(segment
		(start 89.748106 -237.904528)
		(end 89.742264 -237.900972)
		(width 0.088646)
		(layer "In4.Cu")
		(net "M_C_CPU1_SB_CB<1>")
	)
	(segment
		(start 84.12099 -238.774224)
		(end 84.12099 -238.774478)
		(width 0.088646)
		(layer "In4.Cu")
		(net "M_C_CPU1_SB_CB<1>")
	)
	(segment
		(start 90.687906 -237.904528)
		(end 90.682064 -237.900972)
		(width 0.088646)
		(layer "In4.Cu")
		(net "M_C_CPU1_SB_CB<1>")
	)
	(segment
		(start 33.770062 -232.675176)
		(end 33.587182 -232.858056)
		(width 0.18288)
		(layer "In4.Cu")
		(net "M_C_CPU1_SB_CB<1>")
	)
	(segment
		(start 55.992522 -233.554016)
		(end 53.501544 -233.554016)
		(width 0.18288)
		(layer "In4.Cu")
		(net "M_C_CPU1_SB_CB<1>")
	)
	(segment
		(start 33.587182 -232.858056)
		(end 33.587182 -233.258868)
		(width 0.18288)
		(layer "In4.Cu")
		(net "M_C_CPU1_SB_CB<1>")
	)
	(segment
		(start 88.808306 -237.904528)
		(end 88.802464 -237.900972)
		(width 0.088646)
		(layer "In4.Cu")
		(net "M_C_CPU1_SB_CB<1>")
	)
	(segment
		(start 49.708562 -233.441748)
		(end 34.460942 -233.441748)
		(width 0.18288)
		(layer "In4.Cu")
		(net "M_C_CPU1_SB_CB<1>")
	)
	(segment
		(start 63.038736 -233.70921)
		(end 59.423554 -233.70921)
		(width 0.18288)
		(layer "In4.Cu")
		(net "M_C_CPU1_SB_CB<1>")
	)
	(segment
		(start 90.682064 -237.900972)
		(end 90.676222 -237.89767)
		(width 0.088646)
		(layer "In4.Cu")
		(net "M_C_CPU1_SB_CB<1>")
	)
	(segment
		(start 33.587182 -233.258868)
		(end 33.404302 -233.441748)
		(width 0.18288)
		(layer "In4.Cu")
		(net "M_C_CPU1_SB_CB<1>")
	)
	(segment
		(start 88.802464 -237.900972)
		(end 88.798654 -237.89894)
		(width 0.088646)
		(layer "In4.Cu")
		(net "M_C_CPU1_SB_CB<1>")
	)
	(segment
		(start 85.608668 -237.901226)
		(end 85.599778 -237.906306)
		(width 0.088646)
		(layer "In4.Cu")
		(net "M_C_CPU1_SB_CB<1>")
	)
	(segment
		(start 34.460942 -233.441748)
		(end 34.278062 -233.258868)
		(width 0.18288)
		(layer "In4.Cu")
		(net "M_C_CPU1_SB_CB<1>")
	)
	(segment
		(start 92.374212 -238.225584)
		(end 92.68714 -238.225584)
		(width 0.088646)
		(layer "In4.Cu")
		(net "M_C_CPU1_SB_CB<1>")
	)
	(segment
		(start 91.627706 -237.904528)
		(end 91.621864 -237.900972)
		(width 0.088646)
		(layer "In4.Cu")
		(net "M_C_CPU1_SB_CB<1>")
	)
	(segment
		(start 33.404302 -233.441748)
		(end 32.301688 -233.441748)
		(width 0.18288)
		(layer "In4.Cu")
		(net "M_C_CPU1_SB_CB<1>")
	)
	(segment
		(start 66.897758 -234.973368)
		(end 64.981836 -234.973368)
		(width 0.18288)
		(layer "In4.Cu")
		(net "M_C_CPU1_SB_CB<1>")
	)
	(segment
		(start 34.278062 -232.858056)
		(end 34.095182 -232.675176)
		(width 0.18288)
		(layer "In4.Cu")
		(net "M_C_CPU1_SB_CB<1>")
	)
	(segment
		(start 92.68714 -238.225584)
		(end 92.744544 -238.16818)
		(width 0.088646)
		(layer "In4.Cu")
		(net "M_C_CPU1_SB_CB<1>")
	)
	(segment
		(start 83.064096 -238.97463)
		(end 71.825358 -238.97463)
		(width 0.18288)
		(layer "In4.Cu")
		(net "M_C_CPU1_SB_CB<1>")
	)
	(segment
		(start 67.82435 -234.973114)
		(end 66.898012 -234.973114)
		(width 0.18288)
		(layer "In4.Cu")
		(net "M_C_CPU1_SB_CB<1>")
	)
	(segment
		(start 34.095182 -232.675176)
		(end 33.770062 -232.675176)
		(width 0.18288)
		(layer "In4.Cu")
		(net "M_C_CPU1_SB_CB<1>")
	)
	(segment
		(start 64.981836 -234.973368)
		(end 64.442086 -234.433618)
		(width 0.18288)
		(layer "In4.Cu")
		(net "M_C_CPU1_SB_CB<1>")
	)
	(segment
		(start 83.920838 -238.97463)
		(end 83.064096 -238.97463)
		(width 0.088646)
		(layer "In4.Cu")
		(net "M_C_CPU1_SB_CB<1>")
	)
	(segment
		(start 87.862664 -237.900972)
		(end 87.862664 -237.901226)
		(width 0.088646)
		(layer "In4.Cu")
		(net "M_C_CPU1_SB_CB<1>")
	)
	(segment
		(start 71.825358 -238.97463)
		(end 67.82435 -234.973114)
		(width 0.18288)
		(layer "In4.Cu")
		(net "M_C_CPU1_SB_CB<1>")
	)
	(segment
		(start 52.539392 -232.591864)
		(end 50.558446 -232.591864)
		(width 0.18288)
		(layer "In4.Cu")
		(net "M_C_CPU1_SB_CB<1>")
	)
	(segment
		(start 32.301688 -233.441748)
		(end 31.876746 -233.86669)
		(width 0.18288)
		(layer "In4.Cu")
		(net "M_C_CPU1_SB_CB<1>")
	)
	(segment
		(start 63.763144 -234.433618)
		(end 63.038736 -233.70921)
		(width 0.18288)
		(layer "In4.Cu")
		(net "M_C_CPU1_SB_CB<1>")
	)
	(segment
		(start 66.898012 -234.973114)
		(end 66.897758 -234.973368)
		(width 0.18288)
		(layer "In4.Cu")
		(net "M_C_CPU1_SB_CB<1>")
	)
	(segment
		(start 50.558446 -232.591864)
		(end 49.708562 -233.441748)
		(width 0.18288)
		(layer "In4.Cu")
		(net "M_C_CPU1_SB_CB<1>")
	)
	(segment
		(start 92.561664 -237.900972)
		(end 92.555822 -237.89767)
		(width 0.088646)
		(layer "In4.Cu")
		(net "M_C_CPU1_SB_CB<1>")
	)
	(segment
		(start 92.566744 -237.90402)
		(end 92.561664 -237.900972)
		(width 0.088646)
		(layer "In4.Cu")
		(net "M_C_CPU1_SB_CB<1>")
	)
	(segment
		(start 53.501544 -233.554016)
		(end 52.539392 -232.591864)
		(width 0.18288)
		(layer "In4.Cu")
		(net "M_C_CPU1_SB_CB<1>")
	)
	(segment
		(start 59.423554 -233.70921)
		(end 59.062874 -233.34853)
		(width 0.18288)
		(layer "In4.Cu")
		(net "M_C_CPU1_SB_CB<1>")
	)
	(segment
		(start 59.062874 -233.34853)
		(end 56.198008 -233.34853)
		(width 0.18288)
		(layer "In4.Cu")
		(net "M_C_CPU1_SB_CB<1>")
	)
	(segment
		(start 56.198008 -233.34853)
		(end 55.992522 -233.554016)
		(width 0.18288)
		(layer "In4.Cu")
		(net "M_C_CPU1_SB_CB<1>")
	)
	(segment
		(start 64.442086 -234.433618)
		(end 63.763144 -234.433618)
		(width 0.18288)
		(layer "In4.Cu")
		(net "M_C_CPU1_SB_CB<1>")
	)
	(segment
		(start 89.742264 -237.900972)
		(end 89.736422 -237.89767)
		(width 0.088646)
		(layer "In4.Cu")
		(net "M_C_CPU1_SB_CB<1>")
	)
	(arc
		(start 85.599778 -237.906306)
		(mid 85.468864 -238.042666)
		(end 85.421216 -238.225584)
		(width 0.088646)
		(layer "In4.Cu")
		(net "M_C_CPU1_SB_CB<1>")
	)
	(arc
		(start 88.798654 -237.89894)
		(mid 88.612964 -237.850862)
		(end 88.427814 -237.900972)
		(width 0.088646)
		(layer "In4.Cu")
		(net "M_C_CPU1_SB_CB<1>")
	)
	(arc
		(start 89.736422 -237.89767)
		(mid 89.551567 -237.850752)
		(end 89.367614 -237.900972)
		(width 0.088646)
		(layer "In4.Cu")
		(net "M_C_CPU1_SB_CB<1>")
	)
	(arc
		(start 89.367614 -237.900972)
		(mid 89.08844 -237.976771)
		(end 88.808306 -237.904528)
		(width 0.088646)
		(layer "In4.Cu")
		(net "M_C_CPU1_SB_CB<1>")
	)
	(arc
		(start 91.247214 -237.900972)
		(mid 90.96804 -237.976771)
		(end 90.687906 -237.904528)
		(width 0.088646)
		(layer "In4.Cu")
		(net "M_C_CPU1_SB_CB<1>")
	)
	(arc
		(start 84.573364 -238.715042)
		(mid 84.386166 -238.664899)
		(end 84.198968 -238.715042)
		(width 0.088646)
		(layer "In4.Cu")
		(net "M_C_CPU1_SB_CB<1>")
	)
	(arc
		(start 84.198968 -238.715042)
		(mid 84.158038 -238.742075)
		(end 84.12099 -238.774224)
		(width 0.088646)
		(layer "In4.Cu")
		(net "M_C_CPU1_SB_CB<1>")
	)
	(arc
		(start 90.307414 -237.900972)
		(mid 90.02824 -237.976771)
		(end 89.748106 -237.904528)
		(width 0.088646)
		(layer "In4.Cu")
		(net "M_C_CPU1_SB_CB<1>")
	)
	(arc
		(start 85.983064 -237.901226)
		(mid 85.795866 -237.851083)
		(end 85.608668 -237.901226)
		(width 0.088646)
		(layer "In4.Cu")
		(net "M_C_CPU1_SB_CB<1>")
	)
	(arc
		(start 85.138768 -238.715042)
		(mid 84.856066 -238.790818)
		(end 84.573364 -238.715042)
		(width 0.088646)
		(layer "In4.Cu")
		(net "M_C_CPU1_SB_CB<1>")
	)
	(arc
		(start 87.862664 -237.901226)
		(mid 87.675466 -237.851083)
		(end 87.488268 -237.901226)
		(width 0.088646)
		(layer "In4.Cu")
		(net "M_C_CPU1_SB_CB<1>")
	)
	(arc
		(start 88.427814 -237.900972)
		(mid 88.145256 -237.976621)
		(end 87.862664 -237.900972)
		(width 0.088646)
		(layer "In4.Cu")
		(net "M_C_CPU1_SB_CB<1>")
	)
	(arc
		(start 87.488268 -237.901226)
		(mid 87.214069 -237.977061)
		(end 86.937596 -237.909862)
		(width 0.088646)
		(layer "In4.Cu")
		(net "M_C_CPU1_SB_CB<1>")
	)
	(arc
		(start 86.922864 -237.901226)
		(mid 86.735666 -237.851083)
		(end 86.548468 -237.901226)
		(width 0.088646)
		(layer "In4.Cu")
		(net "M_C_CPU1_SB_CB<1>")
	)
	(arc
		(start 92.555822 -237.89767)
		(mid 92.370967 -237.850752)
		(end 92.187014 -237.900972)
		(width 0.088646)
		(layer "In4.Cu")
		(net "M_C_CPU1_SB_CB<1>")
	)
	(arc
		(start 92.744544 -238.16818)
		(mid 92.685154 -238.016219)
		(end 92.566744 -237.90402)
		(width 0.088646)
		(layer "In4.Cu")
		(net "M_C_CPU1_SB_CB<1>")
	)
	(arc
		(start 91.616022 -237.89767)
		(mid 91.431167 -237.850752)
		(end 91.247214 -237.900972)
		(width 0.088646)
		(layer "In4.Cu")
		(net "M_C_CPU1_SB_CB<1>")
	)
	(arc
		(start 92.187014 -237.900972)
		(mid 91.90784 -237.976771)
		(end 91.627706 -237.904528)
		(width 0.088646)
		(layer "In4.Cu")
		(net "M_C_CPU1_SB_CB<1>")
	)
	(arc
		(start 90.676222 -237.89767)
		(mid 90.491367 -237.850752)
		(end 90.307414 -237.900972)
		(width 0.088646)
		(layer "In4.Cu")
		(net "M_C_CPU1_SB_CB<1>")
	)
	(arc
		(start 85.421216 -238.23549)
		(mid 85.343105 -238.512439)
		(end 85.138768 -238.715042)
		(width 0.088646)
		(layer "In4.Cu")
		(net "M_C_CPU1_SB_CB<1>")
	)
	(arc
		(start 86.548468 -237.901226)
		(mid 86.265766 -237.977002)
		(end 85.983064 -237.901226)
		(width 0.088646)
		(layer "In4.Cu")
		(net "M_C_CPU1_SB_CB<1>")
	)
	(segment
		(start 23.228046 -235.566712)
		(end 24.562308 -235.566712)
		(width 0.20066)
		(layer "F.Cu")
		(net "M_C_CPU1_SB_CB<0>")
	)
	(segment
		(start 28.598622 -235.14177)
		(end 28.977844 -235.14177)
		(width 0.20066)
		(layer "F.Cu")
		(net "M_C_CPU1_SB_CB<0>")
	)
	(segment
		(start 25.432512 -235.632752)
		(end 25.432512 -235.343192)
		(width 0.20066)
		(layer "F.Cu")
		(net "M_C_CPU1_SB_CB<0>")
	)
	(segment
		(start 28.977844 -235.14177)
		(end 29.402786 -235.566712)
		(width 0.20066)
		(layer "F.Cu")
		(net "M_C_CPU1_SB_CB<0>")
	)
	(segment
		(start 91.904312 -239.57534)
		(end 91.904566 -239.575086)
		(width 0.20066)
		(layer "F.Cu")
		(net "M_C_CPU1_SB_CB<0>")
	)
	(segment
		(start 24.562308 -235.566712)
		(end 24.801068 -235.805472)
		(width 0.20066)
		(layer "F.Cu")
		(net "M_C_CPU1_SB_CB<0>")
	)
	(segment
		(start 31.876746 -235.566712)
		(end 30.771846 -235.566712)
		(width 0.20066)
		(layer "F.Cu")
		(net "M_C_CPU1_SB_CB<0>")
	)
	(segment
		(start 29.402786 -235.566712)
		(end 30.771846 -235.566712)
		(width 0.20066)
		(layer "F.Cu")
		(net "M_C_CPU1_SB_CB<0>")
	)
	(segment
		(start 25.432512 -235.343192)
		(end 25.633934 -235.14177)
		(width 0.20066)
		(layer "F.Cu")
		(net "M_C_CPU1_SB_CB<0>")
	)
	(segment
		(start 28.529026 -235.14177)
		(end 28.598622 -235.14177)
		(width 0.101854)
		(layer "F.Cu")
		(net "M_C_CPU1_SB_CB<0>")
	)
	(segment
		(start 26.069798 -235.14177)
		(end 26.459942 -235.14177)
		(width 0.101854)
		(layer "F.Cu")
		(net "M_C_CPU1_SB_CB<0>")
	)
	(segment
		(start 26.459942 -235.14177)
		(end 28.529026 -235.14177)
		(width 0.1016)
		(layer "F.Cu")
		(net "M_C_CPU1_SB_CB<0>")
	)
	(segment
		(start 91.904566 -239.575086)
		(end 91.904566 -239.0394)
		(width 0.20066)
		(layer "F.Cu")
		(net "M_C_CPU1_SB_CB<0>")
	)
	(segment
		(start 25.633934 -235.14177)
		(end 26.069798 -235.14177)
		(width 0.20066)
		(layer "F.Cu")
		(net "M_C_CPU1_SB_CB<0>")
	)
	(segment
		(start 24.801068 -235.805472)
		(end 25.259792 -235.805472)
		(width 0.20066)
		(layer "F.Cu")
		(net "M_C_CPU1_SB_CB<0>")
	)
	(segment
		(start 25.259792 -235.805472)
		(end 25.432512 -235.632752)
		(width 0.20066)
		(layer "F.Cu")
		(net "M_C_CPU1_SB_CB<0>")
	)
	(segment
		(start 64.362838 -236.076998)
		(end 63.182246 -236.076998)
		(width 0.18288)
		(layer "In4.Cu")
		(net "M_C_CPU1_SB_CB<0>")
	)
	(segment
		(start 83.77555 -239.97031)
		(end 83.064096 -239.97031)
		(width 0.088646)
		(layer "In4.Cu")
		(net "M_C_CPU1_SB_CB<0>")
	)
	(segment
		(start 39.782496 -235.14177)
		(end 38.81628 -236.107986)
		(width 0.18288)
		(layer "In4.Cu")
		(net "M_C_CPU1_SB_CB<0>")
	)
	(segment
		(start 35.037014 -234.95889)
		(end 35.037014 -234.19435)
		(width 0.18288)
		(layer "In4.Cu")
		(net "M_C_CPU1_SB_CB<0>")
	)
	(segment
		(start 89.837514 -238.715042)
		(end 89.830148 -238.71936)
		(width 0.088646)
		(layer "In4.Cu")
		(net "M_C_CPU1_SB_CB<0>")
	)
	(segment
		(start 49.591468 -235.14177)
		(end 39.782496 -235.14177)
		(width 0.18288)
		(layer "In4.Cu")
		(net "M_C_CPU1_SB_CB<0>")
	)
	(segment
		(start 50.441606 -234.291632)
		(end 49.591468 -235.14177)
		(width 0.18288)
		(layer "In4.Cu")
		(net "M_C_CPU1_SB_CB<0>")
	)
	(segment
		(start 85.61451 -239.525302)
		(end 85.608414 -239.528858)
		(width 0.088646)
		(layer "In4.Cu")
		(net "M_C_CPU1_SB_CB<0>")
	)
	(segment
		(start 34.346134 -234.95889)
		(end 34.163254 -235.14177)
		(width 0.18288)
		(layer "In4.Cu")
		(net "M_C_CPU1_SB_CB<0>")
	)
	(segment
		(start 37.065712 -235.14177)
		(end 35.219894 -235.14177)
		(width 0.18288)
		(layer "In4.Cu")
		(net "M_C_CPU1_SB_CB<0>")
	)
	(segment
		(start 71.392288 -239.97031)
		(end 68.02755 -236.605572)
		(width 0.18288)
		(layer "In4.Cu")
		(net "M_C_CPU1_SB_CB<0>")
	)
	(segment
		(start 64.891412 -236.605572)
		(end 64.362838 -236.076998)
		(width 0.18288)
		(layer "In4.Cu")
		(net "M_C_CPU1_SB_CB<0>")
	)
	(segment
		(start 89.842086 -238.712248)
		(end 89.837514 -238.715042)
		(width 0.088646)
		(layer "In4.Cu")
		(net "M_C_CPU1_SB_CB<0>")
	)
	(segment
		(start 83.064096 -239.97031)
		(end 71.392288 -239.97031)
		(width 0.18288)
		(layer "In4.Cu")
		(net "M_C_CPU1_SB_CB<0>")
	)
	(segment
		(start 63.182246 -236.076998)
		(end 62.2681 -235.162852)
		(width 0.18288)
		(layer "In4.Cu")
		(net "M_C_CPU1_SB_CB<0>")
	)
	(segment
		(start 54.074822 -235.754672)
		(end 52.611782 -234.291632)
		(width 0.18288)
		(layer "In4.Cu")
		(net "M_C_CPU1_SB_CB<0>")
	)
	(segment
		(start 62.2681 -235.162852)
		(end 59.339226 -235.162852)
		(width 0.18288)
		(layer "In4.Cu")
		(net "M_C_CPU1_SB_CB<0>")
	)
	(segment
		(start 88.897714 -238.715042)
		(end 88.893142 -238.717582)
		(width 0.088646)
		(layer "In4.Cu")
		(net "M_C_CPU1_SB_CB<0>")
	)
	(segment
		(start 38.031928 -236.107986)
		(end 37.065712 -235.14177)
		(width 0.18288)
		(layer "In4.Cu")
		(net "M_C_CPU1_SB_CB<0>")
	)
	(segment
		(start 90.777314 -238.715042)
		(end 90.769948 -238.71936)
		(width 0.088646)
		(layer "In4.Cu")
		(net "M_C_CPU1_SB_CB<0>")
	)
	(segment
		(start 68.02755 -236.605572)
		(end 64.891412 -236.605572)
		(width 0.18288)
		(layer "In4.Cu")
		(net "M_C_CPU1_SB_CB<0>")
	)
	(segment
		(start 85.608414 -239.528858)
		(end 85.593682 -239.537494)
		(width 0.088646)
		(layer "In4.Cu")
		(net "M_C_CPU1_SB_CB<0>")
	)
	(segment
		(start 88.902286 -238.712248)
		(end 88.897714 -238.715042)
		(width 0.088646)
		(layer "In4.Cu")
		(net "M_C_CPU1_SB_CB<0>")
	)
	(segment
		(start 34.163254 -235.14177)
		(end 32.301688 -235.14177)
		(width 0.18288)
		(layer "In4.Cu")
		(net "M_C_CPU1_SB_CB<0>")
	)
	(segment
		(start 55.207408 -235.754672)
		(end 54.074822 -235.754672)
		(width 0.18288)
		(layer "In4.Cu")
		(net "M_C_CPU1_SB_CB<0>")
	)
	(segment
		(start 34.346134 -234.19435)
		(end 34.346134 -234.95889)
		(width 0.18288)
		(layer "In4.Cu")
		(net "M_C_CPU1_SB_CB<0>")
	)
	(segment
		(start 91.548712 -238.94415)
		(end 91.151964 -238.715042)
		(width 0.088646)
		(layer "In4.Cu")
		(net "M_C_CPU1_SB_CB<0>")
	)
	(segment
		(start 34.529014 -234.01147)
		(end 34.346134 -234.19435)
		(width 0.18288)
		(layer "In4.Cu")
		(net "M_C_CPU1_SB_CB<0>")
	)
	(segment
		(start 84.386166 -239.60455)
		(end 84.14131 -239.60455)
		(width 0.088646)
		(layer "In4.Cu")
		(net "M_C_CPU1_SB_CB<0>")
	)
	(segment
		(start 90.781886 -238.712248)
		(end 90.777314 -238.715042)
		(width 0.088646)
		(layer "In4.Cu")
		(net "M_C_CPU1_SB_CB<0>")
	)
	(segment
		(start 35.219894 -235.14177)
		(end 35.037014 -234.95889)
		(width 0.18288)
		(layer "In4.Cu")
		(net "M_C_CPU1_SB_CB<0>")
	)
	(segment
		(start 86.078568 -238.715042)
		(end 86.069678 -238.720122)
		(width 0.088646)
		(layer "In4.Cu")
		(net "M_C_CPU1_SB_CB<0>")
	)
	(segment
		(start 59.339226 -235.162852)
		(end 59.205368 -235.028994)
		(width 0.18288)
		(layer "In4.Cu")
		(net "M_C_CPU1_SB_CB<0>")
	)
	(segment
		(start 84.14131 -239.60455)
		(end 83.77555 -239.97031)
		(width 0.088646)
		(layer "In4.Cu")
		(net "M_C_CPU1_SB_CB<0>")
	)
	(segment
		(start 91.904566 -239.0394)
		(end 91.904312 -239.0394)
		(width 0.088646)
		(layer "In4.Cu")
		(net "M_C_CPU1_SB_CB<0>")
	)
	(segment
		(start 55.933086 -235.028994)
		(end 55.207408 -235.754672)
		(width 0.18288)
		(layer "In4.Cu")
		(net "M_C_CPU1_SB_CB<0>")
	)
	(segment
		(start 32.301688 -235.14177)
		(end 31.876746 -235.566712)
		(width 0.18288)
		(layer "In4.Cu")
		(net "M_C_CPU1_SB_CB<0>")
	)
	(segment
		(start 34.854134 -234.01147)
		(end 34.529014 -234.01147)
		(width 0.18288)
		(layer "In4.Cu")
		(net "M_C_CPU1_SB_CB<0>")
	)
	(segment
		(start 35.037014 -234.19435)
		(end 34.854134 -234.01147)
		(width 0.18288)
		(layer "In4.Cu")
		(net "M_C_CPU1_SB_CB<0>")
	)
	(segment
		(start 59.205368 -235.028994)
		(end 55.933086 -235.028994)
		(width 0.18288)
		(layer "In4.Cu")
		(net "M_C_CPU1_SB_CB<0>")
	)
	(segment
		(start 38.81628 -236.107986)
		(end 38.031928 -236.107986)
		(width 0.18288)
		(layer "In4.Cu")
		(net "M_C_CPU1_SB_CB<0>")
	)
	(segment
		(start 52.611782 -234.291632)
		(end 50.441606 -234.291632)
		(width 0.18288)
		(layer "In4.Cu")
		(net "M_C_CPU1_SB_CB<0>")
	)
	(arc
		(start 90.769948 -238.71936)
		(mid 90.490487 -238.790797)
		(end 90.212164 -238.715042)
		(width 0.088646)
		(layer "In4.Cu")
		(net "M_C_CPU1_SB_CB<0>")
	)
	(arc
		(start 87.392764 -238.715042)
		(mid 87.205566 -238.664899)
		(end 87.018368 -238.715042)
		(width 0.088646)
		(layer "In4.Cu")
		(net "M_C_CPU1_SB_CB<0>")
	)
	(arc
		(start 91.904312 -239.0394)
		(mid 91.720227 -239.015222)
		(end 91.548712 -238.94415)
		(width 0.088646)
		(layer "In4.Cu")
		(net "M_C_CPU1_SB_CB<0>")
	)
	(arc
		(start 86.069678 -238.720122)
		(mid 85.938764 -238.856482)
		(end 85.891116 -239.0394)
		(width 0.088646)
		(layer "In4.Cu")
		(net "M_C_CPU1_SB_CB<0>")
	)
	(arc
		(start 88.893142 -238.717582)
		(mid 88.612507 -238.79075)
		(end 88.332564 -238.715042)
		(width 0.088646)
		(layer "In4.Cu")
		(net "M_C_CPU1_SB_CB<0>")
	)
	(arc
		(start 87.958168 -238.715042)
		(mid 87.675466 -238.790818)
		(end 87.392764 -238.715042)
		(width 0.088646)
		(layer "In4.Cu")
		(net "M_C_CPU1_SB_CB<0>")
	)
	(arc
		(start 85.593682 -239.537494)
		(mid 85.317207 -239.604814)
		(end 85.04301 -239.528858)
		(width 0.088646)
		(layer "In4.Cu")
		(net "M_C_CPU1_SB_CB<0>")
	)
	(arc
		(start 84.668614 -239.528858)
		(mid 84.532372 -239.585292)
		(end 84.386166 -239.60455)
		(width 0.088646)
		(layer "In4.Cu")
		(net "M_C_CPU1_SB_CB<0>")
	)
	(arc
		(start 87.018368 -238.715042)
		(mid 86.735666 -238.790818)
		(end 86.452964 -238.715042)
		(width 0.088646)
		(layer "In4.Cu")
		(net "M_C_CPU1_SB_CB<0>")
	)
	(arc
		(start 85.891116 -239.0394)
		(mid 85.817125 -239.318966)
		(end 85.61451 -239.525302)
		(width 0.088646)
		(layer "In4.Cu")
		(net "M_C_CPU1_SB_CB<0>")
	)
	(arc
		(start 89.830148 -238.71936)
		(mid 89.550687 -238.790797)
		(end 89.272364 -238.715042)
		(width 0.088646)
		(layer "In4.Cu")
		(net "M_C_CPU1_SB_CB<0>")
	)
	(arc
		(start 91.151964 -238.715042)
		(mid 90.9673 -238.664782)
		(end 90.781886 -238.712248)
		(width 0.088646)
		(layer "In4.Cu")
		(net "M_C_CPU1_SB_CB<0>")
	)
	(arc
		(start 88.332564 -238.715042)
		(mid 88.145366 -238.664899)
		(end 87.958168 -238.715042)
		(width 0.088646)
		(layer "In4.Cu")
		(net "M_C_CPU1_SB_CB<0>")
	)
	(arc
		(start 86.452964 -238.715042)
		(mid 86.265766 -238.664899)
		(end 86.078568 -238.715042)
		(width 0.088646)
		(layer "In4.Cu")
		(net "M_C_CPU1_SB_CB<0>")
	)
	(arc
		(start 89.272364 -238.715042)
		(mid 89.0877 -238.664782)
		(end 88.902286 -238.712248)
		(width 0.088646)
		(layer "In4.Cu")
		(net "M_C_CPU1_SB_CB<0>")
	)
	(arc
		(start 90.212164 -238.715042)
		(mid 90.0275 -238.664782)
		(end 89.842086 -238.712248)
		(width 0.088646)
		(layer "In4.Cu")
		(net "M_C_CPU1_SB_CB<0>")
	)
	(arc
		(start 85.04301 -239.528858)
		(mid 84.855812 -239.478715)
		(end 84.668614 -239.528858)
		(width 0.088646)
		(layer "In4.Cu")
		(net "M_C_CPU1_SB_CB<0>")
	)
	(segment
		(start 28.529026 -247.04167)
		(end 28.707588 -247.04167)
		(width 0.20066)
		(layer "F.Cu")
		(net "M_C_CPU1_SB_CA<6>")
	)
	(segment
		(start 24.562308 -247.466612)
		(end 24.773636 -247.67794)
		(width 0.20066)
		(layer "F.Cu")
		(net "M_C_CPU1_SB_CA<6>")
	)
	(segment
		(start 28.707588 -247.04167)
		(end 29.13253 -247.466612)
		(width 0.20066)
		(layer "F.Cu")
		(net "M_C_CPU1_SB_CA<6>")
	)
	(segment
		(start 31.876746 -247.466612)
		(end 30.771846 -247.466612)
		(width 0.20066)
		(layer "F.Cu")
		(net "M_C_CPU1_SB_CA<6>")
	)
	(segment
		(start 23.228046 -247.466612)
		(end 24.562308 -247.466612)
		(width 0.20066)
		(layer "F.Cu")
		(net "M_C_CPU1_SB_CA<6>")
	)
	(segment
		(start 25.432512 -247.19534)
		(end 25.595072 -247.03278)
		(width 0.20066)
		(layer "F.Cu")
		(net "M_C_CPU1_SB_CA<6>")
	)
	(segment
		(start 26.20391 -247.03278)
		(end 26.2128 -247.04167)
		(width 0.1016)
		(layer "F.Cu")
		(net "M_C_CPU1_SB_CA<6>")
	)
	(segment
		(start 25.432512 -247.523508)
		(end 25.432512 -247.19534)
		(width 0.20066)
		(layer "F.Cu")
		(net "M_C_CPU1_SB_CA<6>")
	)
	(segment
		(start 25.27808 -247.67794)
		(end 25.432512 -247.523508)
		(width 0.20066)
		(layer "F.Cu")
		(net "M_C_CPU1_SB_CA<6>")
	)
	(segment
		(start 91.434666 -245.27256)
		(end 91.434412 -245.272306)
		(width 0.20066)
		(layer "F.Cu")
		(net "M_C_CPU1_SB_CA<6>")
	)
	(segment
		(start 24.773636 -247.67794)
		(end 25.27808 -247.67794)
		(width 0.20066)
		(layer "F.Cu")
		(net "M_C_CPU1_SB_CA<6>")
	)
	(segment
		(start 29.13253 -247.466612)
		(end 30.771846 -247.466612)
		(width 0.20066)
		(layer "F.Cu")
		(net "M_C_CPU1_SB_CA<6>")
	)
	(segment
		(start 25.595072 -247.03278)
		(end 26.20391 -247.03278)
		(width 0.20066)
		(layer "F.Cu")
		(net "M_C_CPU1_SB_CA<6>")
	)
	(segment
		(start 26.2128 -247.04167)
		(end 28.198318 -247.04167)
		(width 0.1016)
		(layer "F.Cu")
		(net "M_C_CPU1_SB_CA<6>")
	)
	(segment
		(start 28.198318 -247.04167)
		(end 28.529026 -247.04167)
		(width 0.101854)
		(layer "F.Cu")
		(net "M_C_CPU1_SB_CA<6>")
	)
	(segment
		(start 91.434412 -245.272306)
		(end 91.434412 -244.73662)
		(width 0.20066)
		(layer "F.Cu")
		(net "M_C_CPU1_SB_CA<6>")
	)
	(segment
		(start 65.625472 -247.718326)
		(end 65.465452 -247.558306)
		(width 0.18288)
		(layer "In4.Cu")
		(net "M_C_CPU1_SB_CA<6>")
	)
	(segment
		(start 41.70553 -248.243852)
		(end 41.353486 -247.891808)
		(width 0.18288)
		(layer "In4.Cu")
		(net "M_C_CPU1_SB_CA<6>")
	)
	(segment
		(start 88.889332 -245.231158)
		(end 88.8873 -245.232428)
		(width 0.088646)
		(layer "In4.Cu")
		(net "M_C_CPU1_SB_CA<6>")
	)
	(segment
		(start 64.957452 -247.731788)
		(end 64.797432 -247.891808)
		(width 0.18288)
		(layer "In4.Cu")
		(net "M_C_CPU1_SB_CA<6>")
	)
	(segment
		(start 65.117472 -247.558306)
		(end 64.957452 -247.718326)
		(width 0.18288)
		(layer "In4.Cu")
		(net "M_C_CPU1_SB_CA<6>")
	)
	(segment
		(start 87.407496 -245.234968)
		(end 87.392764 -245.226332)
		(width 0.088646)
		(layer "In4.Cu")
		(net "M_C_CPU1_SB_CA<6>")
	)
	(segment
		(start 36.148772 -247.891808)
		(end 32.301942 -247.891808)
		(width 0.18288)
		(layer "In4.Cu")
		(net "M_C_CPU1_SB_CA<6>")
	)
	(segment
		(start 90.806778 -245.209314)
		(end 90.792808 -245.217188)
		(width 0.088646)
		(layer "In4.Cu")
		(net "M_C_CPU1_SB_CA<6>")
	)
	(segment
		(start 86.361016 -246.364506)
		(end 86.361016 -246.374412)
		(width 0.088646)
		(layer "In4.Cu")
		(net "M_C_CPU1_SB_CA<6>")
	)
	(segment
		(start 38.571932 -247.891808)
		(end 38.411404 -247.73128)
		(width 0.18288)
		(layer "In4.Cu")
		(net "M_C_CPU1_SB_CA<6>")
	)
	(segment
		(start 90.777314 -245.226332)
		(end 90.7669 -245.232428)
		(width 0.088646)
		(layer "In4.Cu")
		(net "M_C_CPU1_SB_CA<6>")
	)
	(segment
		(start 36.3093 -247.73128)
		(end 36.148772 -247.891808)
		(width 0.18288)
		(layer "In4.Cu")
		(net "M_C_CPU1_SB_CA<6>")
	)
	(segment
		(start 90.792808 -245.217188)
		(end 90.777314 -245.226332)
		(width 0.088646)
		(layer "In4.Cu")
		(net "M_C_CPU1_SB_CA<6>")
	)
	(segment
		(start 40.660066 -248.243852)
		(end 40.31869 -248.243852)
		(width 0.18288)
		(layer "In4.Cu")
		(net "M_C_CPU1_SB_CA<6>")
	)
	(segment
		(start 64.797432 -247.891808)
		(end 42.39895 -247.891808)
		(width 0.18288)
		(layer "In4.Cu")
		(net "M_C_CPU1_SB_CA<6>")
	)
	(segment
		(start 40.31869 -248.243852)
		(end 39.966646 -247.891808)
		(width 0.18288)
		(layer "In4.Cu")
		(net "M_C_CPU1_SB_CA<6>")
	)
	(segment
		(start 32.301942 -247.891808)
		(end 31.876746 -247.466612)
		(width 0.18288)
		(layer "In4.Cu")
		(net "M_C_CPU1_SB_CA<6>")
	)
	(segment
		(start 91.434412 -244.73662)
		(end 90.806778 -245.209314)
		(width 0.088646)
		(layer "In4.Cu")
		(net "M_C_CPU1_SB_CA<6>")
	)
	(segment
		(start 65.625472 -248.032524)
		(end 65.625472 -247.718326)
		(width 0.18288)
		(layer "In4.Cu")
		(net "M_C_CPU1_SB_CA<6>")
	)
	(segment
		(start 83.730846 -247.01119)
		(end 83.06435 -247.01119)
		(width 0.088646)
		(layer "In4.Cu")
		(net "M_C_CPU1_SB_CA<6>")
	)
	(segment
		(start 65.465452 -247.558306)
		(end 65.117472 -247.558306)
		(width 0.18288)
		(layer "In4.Cu")
		(net "M_C_CPU1_SB_CA<6>")
	)
	(segment
		(start 41.01211 -247.891808)
		(end 40.660066 -248.243852)
		(width 0.18288)
		(layer "In4.Cu")
		(net "M_C_CPU1_SB_CA<6>")
	)
	(segment
		(start 83.81238 -246.929656)
		(end 83.730846 -247.01119)
		(width 0.088646)
		(layer "In4.Cu")
		(net "M_C_CPU1_SB_CA<6>")
	)
	(segment
		(start 38.411404 -247.73128)
		(end 36.3093 -247.73128)
		(width 0.18288)
		(layer "In4.Cu")
		(net "M_C_CPU1_SB_CA<6>")
	)
	(segment
		(start 86.830916 -245.55069)
		(end 86.830916 -245.560596)
		(width 0.088646)
		(layer "In4.Cu")
		(net "M_C_CPU1_SB_CA<6>")
	)
	(segment
		(start 83.916266 -246.929656)
		(end 83.81238 -246.929656)
		(width 0.088646)
		(layer "In4.Cu")
		(net "M_C_CPU1_SB_CA<6>")
	)
	(segment
		(start 66.359024 -248.192544)
		(end 65.785492 -248.192544)
		(width 0.18288)
		(layer "In4.Cu")
		(net "M_C_CPU1_SB_CA<6>")
	)
	(segment
		(start 64.957452 -247.718326)
		(end 64.957452 -247.731788)
		(width 0.18288)
		(layer "In4.Cu")
		(net "M_C_CPU1_SB_CA<6>")
	)
	(segment
		(start 67.540378 -247.01119)
		(end 66.359024 -248.192544)
		(width 0.18288)
		(layer "In4.Cu")
		(net "M_C_CPU1_SB_CA<6>")
	)
	(segment
		(start 86.548468 -246.040148)
		(end 86.539578 -246.045228)
		(width 0.088646)
		(layer "In4.Cu")
		(net "M_C_CPU1_SB_CA<6>")
	)
	(segment
		(start 88.897968 -245.226332)
		(end 88.889332 -245.231158)
		(width 0.088646)
		(layer "In4.Cu")
		(net "M_C_CPU1_SB_CA<6>")
	)
	(segment
		(start 83.06435 -247.01119)
		(end 67.540378 -247.01119)
		(width 0.18288)
		(layer "In4.Cu")
		(net "M_C_CPU1_SB_CA<6>")
	)
	(segment
		(start 39.966646 -247.891808)
		(end 38.571932 -247.891808)
		(width 0.18288)
		(layer "In4.Cu")
		(net "M_C_CPU1_SB_CA<6>")
	)
	(segment
		(start 42.39895 -247.891808)
		(end 42.046906 -248.243852)
		(width 0.18288)
		(layer "In4.Cu")
		(net "M_C_CPU1_SB_CA<6>")
	)
	(segment
		(start 41.353486 -247.891808)
		(end 41.01211 -247.891808)
		(width 0.18288)
		(layer "In4.Cu")
		(net "M_C_CPU1_SB_CA<6>")
	)
	(segment
		(start 89.287096 -245.234968)
		(end 89.272364 -245.226332)
		(width 0.088646)
		(layer "In4.Cu")
		(net "M_C_CPU1_SB_CA<6>")
	)
	(segment
		(start 42.046906 -248.243852)
		(end 41.70553 -248.243852)
		(width 0.18288)
		(layer "In4.Cu")
		(net "M_C_CPU1_SB_CA<6>")
	)
	(segment
		(start 87.018368 -245.226332)
		(end 87.009478 -245.231412)
		(width 0.088646)
		(layer "In4.Cu")
		(net "M_C_CPU1_SB_CA<6>")
	)
	(segment
		(start 65.785492 -248.192544)
		(end 65.625472 -248.032524)
		(width 0.18288)
		(layer "In4.Cu")
		(net "M_C_CPU1_SB_CA<6>")
	)
	(arc
		(start 86.539578 -246.045228)
		(mid 86.408664 -246.181588)
		(end 86.361016 -246.364506)
		(width 0.088646)
		(layer "In4.Cu")
		(net "M_C_CPU1_SB_CA<6>")
	)
	(arc
		(start 90.7669 -245.232428)
		(mid 90.488722 -245.30212)
		(end 90.212164 -245.226332)
		(width 0.088646)
		(layer "In4.Cu")
		(net "M_C_CPU1_SB_CA<6>")
	)
	(arc
		(start 84.198968 -246.853964)
		(mid 84.062599 -246.910406)
		(end 83.916266 -246.929656)
		(width 0.088646)
		(layer "In4.Cu")
		(net "M_C_CPU1_SB_CA<6>")
	)
	(arc
		(start 88.8873 -245.232428)
		(mid 88.609122 -245.30212)
		(end 88.332564 -245.226332)
		(width 0.088646)
		(layer "In4.Cu")
		(net "M_C_CPU1_SB_CA<6>")
	)
	(arc
		(start 87.009478 -245.231412)
		(mid 86.878564 -245.367772)
		(end 86.830916 -245.55069)
		(width 0.088646)
		(layer "In4.Cu")
		(net "M_C_CPU1_SB_CA<6>")
	)
	(arc
		(start 87.958168 -245.226332)
		(mid 87.683939 -245.302257)
		(end 87.407496 -245.234968)
		(width 0.088646)
		(layer "In4.Cu")
		(net "M_C_CPU1_SB_CA<6>")
	)
	(arc
		(start 85.138768 -246.853964)
		(mid 84.856066 -246.92974)
		(end 84.573364 -246.853964)
		(width 0.088646)
		(layer "In4.Cu")
		(net "M_C_CPU1_SB_CA<6>")
	)
	(arc
		(start 87.392764 -245.226332)
		(mid 87.205566 -245.176189)
		(end 87.018368 -245.226332)
		(width 0.088646)
		(layer "In4.Cu")
		(net "M_C_CPU1_SB_CA<6>")
	)
	(arc
		(start 89.272364 -245.226332)
		(mid 89.085166 -245.176189)
		(end 88.897968 -245.226332)
		(width 0.088646)
		(layer "In4.Cu")
		(net "M_C_CPU1_SB_CA<6>")
	)
	(arc
		(start 86.830916 -245.560596)
		(mid 86.752805 -245.837545)
		(end 86.548468 -246.040148)
		(width 0.088646)
		(layer "In4.Cu")
		(net "M_C_CPU1_SB_CA<6>")
	)
	(arc
		(start 85.513164 -246.853964)
		(mid 85.325966 -246.803821)
		(end 85.138768 -246.853964)
		(width 0.088646)
		(layer "In4.Cu")
		(net "M_C_CPU1_SB_CA<6>")
	)
	(arc
		(start 84.573364 -246.853964)
		(mid 84.386166 -246.803821)
		(end 84.198968 -246.853964)
		(width 0.088646)
		(layer "In4.Cu")
		(net "M_C_CPU1_SB_CA<6>")
	)
	(arc
		(start 90.212164 -245.226332)
		(mid 90.024966 -245.176189)
		(end 89.837768 -245.226332)
		(width 0.088646)
		(layer "In4.Cu")
		(net "M_C_CPU1_SB_CA<6>")
	)
	(arc
		(start 89.837768 -245.226332)
		(mid 89.563539 -245.302257)
		(end 89.287096 -245.234968)
		(width 0.088646)
		(layer "In4.Cu")
		(net "M_C_CPU1_SB_CA<6>")
	)
	(arc
		(start 86.361016 -246.374412)
		(mid 86.282905 -246.651361)
		(end 86.078568 -246.853964)
		(width 0.088646)
		(layer "In4.Cu")
		(net "M_C_CPU1_SB_CA<6>")
	)
	(arc
		(start 88.332564 -245.226332)
		(mid 88.145366 -245.176189)
		(end 87.958168 -245.226332)
		(width 0.088646)
		(layer "In4.Cu")
		(net "M_C_CPU1_SB_CA<6>")
	)
	(arc
		(start 86.078568 -246.853964)
		(mid 85.795866 -246.92974)
		(end 85.513164 -246.853964)
		(width 0.088646)
		(layer "In4.Cu")
		(net "M_C_CPU1_SB_CA<6>")
	)
	(segment
		(start 29.899864 -248.741692)
		(end 31.972758 -248.741692)
		(width 0.1016)
		(layer "F.Cu")
		(net "M_C_CPU1_SB_CA<5>")
	)
	(segment
		(start 93.784166 -246.086376)
		(end 93.784166 -245.55069)
		(width 0.20066)
		(layer "F.Cu")
		(net "M_C_CPU1_SB_CA<5>")
	)
	(segment
		(start 29.661866 -248.741692)
		(end 29.899864 -248.741692)
		(width 0.101854)
		(layer "F.Cu")
		(net "M_C_CPU1_SB_CA<5>")
	)
	(segment
		(start 32.666178 -248.592594)
		(end 32.666178 -248.440956)
		(width 0.20066)
		(layer "F.Cu")
		(net "M_C_CPU1_SB_CA<5>")
	)
	(segment
		(start 32.51708 -248.741692)
		(end 32.666178 -248.592594)
		(width 0.20066)
		(layer "F.Cu")
		(net "M_C_CPU1_SB_CA<5>")
	)
	(segment
		(start 32.666178 -248.440956)
		(end 32.794702 -248.312432)
		(width 0.20066)
		(layer "F.Cu")
		(net "M_C_CPU1_SB_CA<5>")
	)
	(segment
		(start 31.972758 -248.741692)
		(end 32.51708 -248.741692)
		(width 0.20066)
		(layer "F.Cu")
		(net "M_C_CPU1_SB_CA<5>")
	)
	(segment
		(start 29.151326 -248.613422)
		(end 29.29382 -248.755916)
		(width 0.20066)
		(layer "F.Cu")
		(net "M_C_CPU1_SB_CA<5>")
	)
	(segment
		(start 29.151326 -248.442734)
		(end 29.151326 -248.613422)
		(width 0.20066)
		(layer "F.Cu")
		(net "M_C_CPU1_SB_CA<5>")
	)
	(segment
		(start 93.783912 -246.08663)
		(end 93.784166 -246.086376)
		(width 0.20066)
		(layer "F.Cu")
		(net "M_C_CPU1_SB_CA<5>")
	)
	(segment
		(start 35.976814 -248.31675)
		(end 34.871914 -248.31675)
		(width 0.20066)
		(layer "F.Cu")
		(net "M_C_CPU1_SB_CA<5>")
	)
	(segment
		(start 33.189926 -248.312432)
		(end 33.401762 -248.524268)
		(width 0.20066)
		(layer "F.Cu")
		(net "M_C_CPU1_SB_CA<5>")
	)
	(segment
		(start 33.848294 -248.524268)
		(end 34.055812 -248.31675)
		(width 0.20066)
		(layer "F.Cu")
		(net "M_C_CPU1_SB_CA<5>")
	)
	(segment
		(start 34.055812 -248.31675)
		(end 34.871914 -248.31675)
		(width 0.20066)
		(layer "F.Cu")
		(net "M_C_CPU1_SB_CA<5>")
	)
	(segment
		(start 33.401762 -248.524268)
		(end 33.848294 -248.524268)
		(width 0.20066)
		(layer "F.Cu")
		(net "M_C_CPU1_SB_CA<5>")
	)
	(segment
		(start 27.328114 -248.31675)
		(end 29.025342 -248.31675)
		(width 0.20066)
		(layer "F.Cu")
		(net "M_C_CPU1_SB_CA<5>")
	)
	(segment
		(start 29.647642 -248.755916)
		(end 29.661866 -248.741692)
		(width 0.101854)
		(layer "F.Cu")
		(net "M_C_CPU1_SB_CA<5>")
	)
	(segment
		(start 29.29382 -248.755916)
		(end 29.647642 -248.755916)
		(width 0.20066)
		(layer "F.Cu")
		(net "M_C_CPU1_SB_CA<5>")
	)
	(segment
		(start 29.025342 -248.31675)
		(end 29.151326 -248.442734)
		(width 0.20066)
		(layer "F.Cu")
		(net "M_C_CPU1_SB_CA<5>")
	)
	(segment
		(start 32.794702 -248.312432)
		(end 33.189926 -248.312432)
		(width 0.20066)
		(layer "F.Cu")
		(net "M_C_CPU1_SB_CA<5>")
	)
	(segment
		(start 61.778642 -248.835418)
		(end 61.550296 -248.607072)
		(width 0.18288)
		(layer "In4.Cu")
		(net "M_C_CPU1_SB_CA<5>")
	)
	(segment
		(start 83.761834 -247.50903)
		(end 83.06435 -247.50903)
		(width 0.088646)
		(layer "In4.Cu")
		(net "M_C_CPU1_SB_CA<5>")
	)
	(segment
		(start 64.595756 -249.017028)
		(end 64.595756 -248.891806)
		(width 0.18288)
		(layer "In4.Cu")
		(net "M_C_CPU1_SB_CA<5>")
	)
	(segment
		(start 91.1606 -245.869968)
		(end 91.15171 -245.875048)
		(width 0.088646)
		(layer "In4.Cu")
		(net "M_C_CPU1_SB_CA<5>")
	)
	(segment
		(start 91.339162 -245.536466)
		(end 91.339162 -245.55069)
		(width 0.088646)
		(layer "In4.Cu")
		(net "M_C_CPU1_SB_CA<5>")
	)
	(segment
		(start 65.286636 -248.891806)
		(end 65.286636 -249.017028)
		(width 0.18288)
		(layer "In4.Cu")
		(net "M_C_CPU1_SB_CA<5>")
	)
	(segment
		(start 53.112416 -248.741692)
		(end 52.719224 -248.741692)
		(width 0.18288)
		(layer "In4.Cu")
		(net "M_C_CPU1_SB_CA<5>")
	)
	(segment
		(start 55.482744 -248.741692)
		(end 55.185056 -249.03938)
		(width 0.18288)
		(layer "In4.Cu")
		(net "M_C_CPU1_SB_CA<5>")
	)
	(segment
		(start 64.412876 -248.708926)
		(end 62.817502 -248.708926)
		(width 0.18288)
		(layer "In4.Cu")
		(net "M_C_CPU1_SB_CA<5>")
	)
	(segment
		(start 64.778636 -249.199908)
		(end 64.595756 -249.017028)
		(width 0.18288)
		(layer "In4.Cu")
		(net "M_C_CPU1_SB_CA<5>")
	)
	(segment
		(start 83.885024 -247.63222)
		(end 83.761834 -247.50903)
		(width 0.088646)
		(layer "In4.Cu")
		(net "M_C_CPU1_SB_CA<5>")
	)
	(segment
		(start 55.185056 -249.03938)
		(end 54.791864 -249.03938)
		(width 0.18288)
		(layer "In4.Cu")
		(net "M_C_CPU1_SB_CA<5>")
	)
	(segment
		(start 59.6392 -248.919492)
		(end 59.32678 -248.607072)
		(width 0.18288)
		(layer "In4.Cu")
		(net "M_C_CPU1_SB_CA<5>")
	)
	(segment
		(start 52.719224 -248.741692)
		(end 52.421536 -249.03938)
		(width 0.18288)
		(layer "In4.Cu")
		(net "M_C_CPU1_SB_CA<5>")
	)
	(segment
		(start 57.990994 -248.607072)
		(end 57.856374 -248.741692)
		(width 0.18288)
		(layer "In4.Cu")
		(net "M_C_CPU1_SB_CA<5>")
	)
	(segment
		(start 36.958016 -248.741692)
		(end 36.533074 -248.31675)
		(width 0.18288)
		(layer "In4.Cu")
		(net "M_C_CPU1_SB_CA<5>")
	)
	(segment
		(start 54.100984 -248.741692)
		(end 53.803296 -249.03938)
		(width 0.18288)
		(layer "In4.Cu")
		(net "M_C_CPU1_SB_CA<5>")
	)
	(segment
		(start 51.730656 -248.741692)
		(end 36.958016 -248.741692)
		(width 0.18288)
		(layer "In4.Cu")
		(net "M_C_CPU1_SB_CA<5>")
	)
	(segment
		(start 73.11517 -249.148854)
		(end 66.854578 -249.148854)
		(width 0.18288)
		(layer "In4.Cu")
		(net "M_C_CPU1_SB_CA<5>")
	)
	(segment
		(start 66.854578 -249.148854)
		(end 66.41465 -248.708926)
		(width 0.18288)
		(layer "In4.Cu")
		(net "M_C_CPU1_SB_CA<5>")
	)
	(segment
		(start 62.817502 -248.708926)
		(end 62.69101 -248.835418)
		(width 0.18288)
		(layer "In4.Cu")
		(net "M_C_CPU1_SB_CA<5>")
	)
	(segment
		(start 65.103756 -249.199908)
		(end 64.778636 -249.199908)
		(width 0.18288)
		(layer "In4.Cu")
		(net "M_C_CPU1_SB_CA<5>")
	)
	(segment
		(start 54.791864 -249.03938)
		(end 54.494176 -248.741692)
		(width 0.18288)
		(layer "In4.Cu")
		(net "M_C_CPU1_SB_CA<5>")
	)
	(segment
		(start 92.731844 -245.114826)
		(end 92.385896 -245.114826)
		(width 0.088646)
		(layer "In4.Cu")
		(net "M_C_CPU1_SB_CA<5>")
	)
	(segment
		(start 60.07862 -248.919492)
		(end 59.6392 -248.919492)
		(width 0.18288)
		(layer "In4.Cu")
		(net "M_C_CPU1_SB_CA<5>")
	)
	(segment
		(start 52.028344 -249.03938)
		(end 51.730656 -248.741692)
		(width 0.18288)
		(layer "In4.Cu")
		(net "M_C_CPU1_SB_CA<5>")
	)
	(segment
		(start 65.469516 -248.708926)
		(end 65.286636 -248.891806)
		(width 0.18288)
		(layer "In4.Cu")
		(net "M_C_CPU1_SB_CA<5>")
	)
	(segment
		(start 61.550296 -248.607072)
		(end 60.39104 -248.607072)
		(width 0.18288)
		(layer "In4.Cu")
		(net "M_C_CPU1_SB_CA<5>")
	)
	(segment
		(start 87.110316 -246.3546)
		(end 87.110316 -246.364506)
		(width 0.088646)
		(layer "In4.Cu")
		(net "M_C_CPU1_SB_CA<5>")
	)
	(segment
		(start 65.286636 -249.017028)
		(end 65.103756 -249.199908)
		(width 0.18288)
		(layer "In4.Cu")
		(net "M_C_CPU1_SB_CA<5>")
	)
	(segment
		(start 54.494176 -248.741692)
		(end 54.100984 -248.741692)
		(width 0.18288)
		(layer "In4.Cu")
		(net "M_C_CPU1_SB_CA<5>")
	)
	(segment
		(start 60.39104 -248.607072)
		(end 60.07862 -248.919492)
		(width 0.18288)
		(layer "In4.Cu")
		(net "M_C_CPU1_SB_CA<5>")
	)
	(segment
		(start 53.803296 -249.03938)
		(end 53.410104 -249.03938)
		(width 0.18288)
		(layer "In4.Cu")
		(net "M_C_CPU1_SB_CA<5>")
	)
	(segment
		(start 88.347296 -245.866412)
		(end 88.332564 -245.875048)
		(width 0.088646)
		(layer "In4.Cu")
		(net "M_C_CPU1_SB_CA<5>")
	)
	(segment
		(start 86.931754 -246.683784)
		(end 86.922864 -246.688864)
		(width 0.088646)
		(layer "In4.Cu")
		(net "M_C_CPU1_SB_CA<5>")
	)
	(segment
		(start 59.32678 -248.607072)
		(end 57.990994 -248.607072)
		(width 0.18288)
		(layer "In4.Cu")
		(net "M_C_CPU1_SB_CA<5>")
	)
	(segment
		(start 86.640416 -247.168416)
		(end 86.640416 -247.178322)
		(width 0.088646)
		(layer "In4.Cu")
		(net "M_C_CPU1_SB_CA<5>")
	)
	(segment
		(start 84.45627 -247.592342)
		(end 84.416392 -247.63222)
		(width 0.088646)
		(layer "In4.Cu")
		(net "M_C_CPU1_SB_CA<5>")
	)
	(segment
		(start 90.222578 -245.868952)
		(end 90.212164 -245.875048)
		(width 0.088646)
		(layer "In4.Cu")
		(net "M_C_CPU1_SB_CA<5>")
	)
	(segment
		(start 52.421536 -249.03938)
		(end 52.028344 -249.03938)
		(width 0.18288)
		(layer "In4.Cu")
		(net "M_C_CPU1_SB_CA<5>")
	)
	(segment
		(start 64.595756 -248.891806)
		(end 64.412876 -248.708926)
		(width 0.18288)
		(layer "In4.Cu")
		(net "M_C_CPU1_SB_CA<5>")
	)
	(segment
		(start 83.06435 -247.50903)
		(end 74.754994 -247.50903)
		(width 0.18288)
		(layer "In4.Cu")
		(net "M_C_CPU1_SB_CA<5>")
	)
	(segment
		(start 66.41465 -248.708926)
		(end 65.469516 -248.708926)
		(width 0.18288)
		(layer "In4.Cu")
		(net "M_C_CPU1_SB_CA<5>")
	)
	(segment
		(start 62.69101 -248.835418)
		(end 61.778642 -248.835418)
		(width 0.18288)
		(layer "In4.Cu")
		(net "M_C_CPU1_SB_CA<5>")
	)
	(segment
		(start 84.416392 -247.63222)
		(end 83.885024 -247.63222)
		(width 0.088646)
		(layer "In4.Cu")
		(net "M_C_CPU1_SB_CA<5>")
	)
	(segment
		(start 36.533074 -248.31675)
		(end 35.976814 -248.31675)
		(width 0.18288)
		(layer "In4.Cu")
		(net "M_C_CPU1_SB_CA<5>")
	)
	(segment
		(start 92.187268 -245.060978)
		(end 92.176854 -245.054882)
		(width 0.088646)
		(layer "In4.Cu")
		(net "M_C_CPU1_SB_CA<5>")
	)
	(segment
		(start 57.856374 -248.741692)
		(end 55.482744 -248.741692)
		(width 0.18288)
		(layer "In4.Cu")
		(net "M_C_CPU1_SB_CA<5>")
	)
	(segment
		(start 89.287096 -245.866412)
		(end 89.272364 -245.875048)
		(width 0.088646)
		(layer "In4.Cu")
		(net "M_C_CPU1_SB_CA<5>")
	)
	(segment
		(start 74.754994 -247.50903)
		(end 73.11517 -249.148854)
		(width 0.18288)
		(layer "In4.Cu")
		(net "M_C_CPU1_SB_CA<5>")
	)
	(segment
		(start 53.410104 -249.03938)
		(end 53.112416 -248.741692)
		(width 0.18288)
		(layer "In4.Cu")
		(net "M_C_CPU1_SB_CA<5>")
	)
	(segment
		(start 86.461854 -247.4976)
		(end 86.452964 -247.50268)
		(width 0.088646)
		(layer "In4.Cu")
		(net "M_C_CPU1_SB_CA<5>")
	)
	(arc
		(start 90.777314 -245.875048)
		(mid 90.500755 -245.799305)
		(end 90.222578 -245.868952)
		(width 0.088646)
		(layer "In4.Cu")
		(net "M_C_CPU1_SB_CA<5>")
	)
	(arc
		(start 86.640416 -247.178322)
		(mid 86.592737 -247.361222)
		(end 86.461854 -247.4976)
		(width 0.088646)
		(layer "In4.Cu")
		(net "M_C_CPU1_SB_CA<5>")
	)
	(arc
		(start 84.573364 -247.50268)
		(mid 84.511886 -247.543682)
		(end 84.45627 -247.592342)
		(width 0.088646)
		(layer "In4.Cu")
		(net "M_C_CPU1_SB_CA<5>")
	)
	(arc
		(start 86.452964 -247.50268)
		(mid 86.265766 -247.552823)
		(end 86.078568 -247.50268)
		(width 0.088646)
		(layer "In4.Cu")
		(net "M_C_CPU1_SB_CA<5>")
	)
	(arc
		(start 85.513164 -247.50268)
		(mid 85.325966 -247.552823)
		(end 85.138768 -247.50268)
		(width 0.088646)
		(layer "In4.Cu")
		(net "M_C_CPU1_SB_CA<5>")
	)
	(arc
		(start 86.922864 -246.688864)
		(mid 86.718529 -246.891469)
		(end 86.640416 -247.168416)
		(width 0.088646)
		(layer "In4.Cu")
		(net "M_C_CPU1_SB_CA<5>")
	)
	(arc
		(start 90.212164 -245.875048)
		(mid 90.024966 -245.925191)
		(end 89.837768 -245.875048)
		(width 0.088646)
		(layer "In4.Cu")
		(net "M_C_CPU1_SB_CA<5>")
	)
	(arc
		(start 86.078568 -247.50268)
		(mid 85.795866 -247.426904)
		(end 85.513164 -247.50268)
		(width 0.088646)
		(layer "In4.Cu")
		(net "M_C_CPU1_SB_CA<5>")
	)
	(arc
		(start 85.138768 -247.50268)
		(mid 84.856066 -247.426904)
		(end 84.573364 -247.50268)
		(width 0.088646)
		(layer "In4.Cu")
		(net "M_C_CPU1_SB_CA<5>")
	)
	(arc
		(start 87.958168 -245.875048)
		(mid 87.675466 -245.799272)
		(end 87.392764 -245.875048)
		(width 0.088646)
		(layer "In4.Cu")
		(net "M_C_CPU1_SB_CA<5>")
	)
	(arc
		(start 92.385896 -245.114826)
		(mid 92.282998 -245.101123)
		(end 92.187268 -245.060978)
		(width 0.088646)
		(layer "In4.Cu")
		(net "M_C_CPU1_SB_CA<5>")
	)
	(arc
		(start 89.272364 -245.875048)
		(mid 89.085166 -245.925191)
		(end 88.897968 -245.875048)
		(width 0.088646)
		(layer "In4.Cu")
		(net "M_C_CPU1_SB_CA<5>")
	)
	(arc
		(start 88.897968 -245.875048)
		(mid 88.623769 -245.799213)
		(end 88.347296 -245.866412)
		(width 0.088646)
		(layer "In4.Cu")
		(net "M_C_CPU1_SB_CA<5>")
	)
	(arc
		(start 87.110316 -246.364506)
		(mid 87.062637 -246.547406)
		(end 86.931754 -246.683784)
		(width 0.088646)
		(layer "In4.Cu")
		(net "M_C_CPU1_SB_CA<5>")
	)
	(arc
		(start 91.15171 -245.875048)
		(mid 90.964512 -245.925191)
		(end 90.777314 -245.875048)
		(width 0.088646)
		(layer "In4.Cu")
		(net "M_C_CPU1_SB_CA<5>")
	)
	(arc
		(start 91.339162 -245.55069)
		(mid 91.291483 -245.73359)
		(end 91.1606 -245.869968)
		(width 0.088646)
		(layer "In4.Cu")
		(net "M_C_CPU1_SB_CA<5>")
	)
	(arc
		(start 87.392764 -245.875048)
		(mid 87.188429 -246.077653)
		(end 87.110316 -246.3546)
		(width 0.088646)
		(layer "In4.Cu")
		(net "M_C_CPU1_SB_CA<5>")
	)
	(arc
		(start 88.332564 -245.875048)
		(mid 88.145366 -245.925191)
		(end 87.958168 -245.875048)
		(width 0.088646)
		(layer "In4.Cu")
		(net "M_C_CPU1_SB_CA<5>")
	)
	(arc
		(start 93.784166 -245.55069)
		(mid 93.301357 -245.228087)
		(end 92.731844 -245.114826)
		(width 0.088646)
		(layer "In4.Cu")
		(net "M_C_CPU1_SB_CA<5>")
	)
	(arc
		(start 91.62161 -245.060978)
		(mid 91.418305 -245.261844)
		(end 91.339162 -245.536466)
		(width 0.088646)
		(layer "In4.Cu")
		(net "M_C_CPU1_SB_CA<5>")
	)
	(arc
		(start 89.837768 -245.875048)
		(mid 89.563569 -245.799213)
		(end 89.287096 -245.866412)
		(width 0.088646)
		(layer "In4.Cu")
		(net "M_C_CPU1_SB_CA<5>")
	)
	(arc
		(start 92.176854 -245.054882)
		(mid 91.898422 -244.985068)
		(end 91.62161 -245.060978)
		(width 0.088646)
		(layer "In4.Cu")
		(net "M_C_CPU1_SB_CA<5>")
	)
	(segment
		(start 23.228046 -249.166634)
		(end 24.562308 -249.166634)
		(width 0.20066)
		(layer "F.Cu")
		(net "M_C_CPU1_SB_CA<4>")
	)
	(segment
		(start 25.27808 -249.377962)
		(end 25.432512 -249.22353)
		(width 0.20066)
		(layer "F.Cu")
		(net "M_C_CPU1_SB_CA<4>")
	)
	(segment
		(start 26.2128 -248.741692)
		(end 28.198318 -248.741692)
		(width 0.1016)
		(layer "F.Cu")
		(net "M_C_CPU1_SB_CA<4>")
	)
	(segment
		(start 25.432512 -249.22353)
		(end 25.432512 -248.895362)
		(width 0.20066)
		(layer "F.Cu")
		(net "M_C_CPU1_SB_CA<4>")
	)
	(segment
		(start 29.13253 -249.166634)
		(end 30.771846 -249.166634)
		(width 0.20066)
		(layer "F.Cu")
		(net "M_C_CPU1_SB_CA<4>")
	)
	(segment
		(start 28.198318 -248.741692)
		(end 28.529026 -248.741692)
		(width 0.101854)
		(layer "F.Cu")
		(net "M_C_CPU1_SB_CA<4>")
	)
	(segment
		(start 24.773636 -249.377962)
		(end 25.27808 -249.377962)
		(width 0.20066)
		(layer "F.Cu")
		(net "M_C_CPU1_SB_CA<4>")
	)
	(segment
		(start 25.432512 -248.895362)
		(end 25.595072 -248.732802)
		(width 0.20066)
		(layer "F.Cu")
		(net "M_C_CPU1_SB_CA<4>")
	)
	(segment
		(start 26.20391 -248.732802)
		(end 26.2128 -248.741692)
		(width 0.1016)
		(layer "F.Cu")
		(net "M_C_CPU1_SB_CA<4>")
	)
	(segment
		(start 25.595072 -248.732802)
		(end 26.20391 -248.732802)
		(width 0.20066)
		(layer "F.Cu")
		(net "M_C_CPU1_SB_CA<4>")
	)
	(segment
		(start 31.876746 -249.166634)
		(end 30.771846 -249.166634)
		(width 0.20066)
		(layer "F.Cu")
		(net "M_C_CPU1_SB_CA<4>")
	)
	(segment
		(start 28.529026 -248.741692)
		(end 28.707588 -248.741692)
		(width 0.20066)
		(layer "F.Cu")
		(net "M_C_CPU1_SB_CA<4>")
	)
	(segment
		(start 91.904312 -246.08663)
		(end 91.904566 -246.086376)
		(width 0.20066)
		(layer "F.Cu")
		(net "M_C_CPU1_SB_CA<4>")
	)
	(segment
		(start 91.904566 -246.086376)
		(end 91.904566 -245.55069)
		(width 0.20066)
		(layer "F.Cu")
		(net "M_C_CPU1_SB_CA<4>")
	)
	(segment
		(start 24.562308 -249.166634)
		(end 24.773636 -249.377962)
		(width 0.20066)
		(layer "F.Cu")
		(net "M_C_CPU1_SB_CA<4>")
	)
	(segment
		(start 28.707588 -248.741692)
		(end 29.13253 -249.166634)
		(width 0.20066)
		(layer "F.Cu")
		(net "M_C_CPU1_SB_CA<4>")
	)
	(segment
		(start 90.307414 -246.040148)
		(end 90.292682 -246.048784)
		(width 0.088646)
		(layer "In4.Cu")
		(net "M_C_CPU1_SB_CA<4>")
	)
	(segment
		(start 87.018368 -246.853964)
		(end 87.009478 -246.859044)
		(width 0.088646)
		(layer "In4.Cu")
		(net "M_C_CPU1_SB_CA<4>")
	)
	(segment
		(start 73.32599 -249.732038)
		(end 65.926208 -249.732038)
		(width 0.18288)
		(layer "In4.Cu")
		(net "M_C_CPU1_SB_CA<4>")
	)
	(segment
		(start 37.005768 -249.590052)
		(end 36.157408 -248.741692)
		(width 0.18288)
		(layer "In4.Cu")
		(net "M_C_CPU1_SB_CA<4>")
	)
	(segment
		(start 32.301688 -248.741692)
		(end 31.876746 -249.166634)
		(width 0.18288)
		(layer "In4.Cu")
		(net "M_C_CPU1_SB_CA<4>")
	)
	(segment
		(start 81.905348 -247.84431)
		(end 75.213718 -247.84431)
		(width 0.18288)
		(layer "In4.Cu")
		(net "M_C_CPU1_SB_CA<4>")
	)
	(segment
		(start 82.250534 -248.189496)
		(end 81.905348 -247.84431)
		(width 0.18288)
		(layer "In4.Cu")
		(net "M_C_CPU1_SB_CA<4>")
	)
	(segment
		(start 75.213718 -247.84431)
		(end 73.32599 -249.732038)
		(width 0.18288)
		(layer "In4.Cu")
		(net "M_C_CPU1_SB_CA<4>")
	)
	(segment
		(start 45.228764 -249.590052)
		(end 37.005768 -249.590052)
		(width 0.18288)
		(layer "In4.Cu")
		(net "M_C_CPU1_SB_CA<4>")
	)
	(segment
		(start 36.157408 -248.741692)
		(end 32.301688 -248.741692)
		(width 0.18288)
		(layer "In4.Cu")
		(net "M_C_CPU1_SB_CA<4>")
	)
	(segment
		(start 86.830916 -247.178322)
		(end 86.830916 -247.188228)
		(width 0.088646)
		(layer "In4.Cu")
		(net "M_C_CPU1_SB_CA<4>")
	)
	(segment
		(start 61.848492 -249.432826)
		(end 61.689488 -249.59183)
		(width 0.18288)
		(layer "In4.Cu")
		(net "M_C_CPU1_SB_CA<4>")
	)
	(segment
		(start 88.427814 -246.040148)
		(end 88.4174 -246.046244)
		(width 0.088646)
		(layer "In4.Cu")
		(net "M_C_CPU1_SB_CA<4>")
	)
	(segment
		(start 84.128356 -248.189496)
		(end 83.06435 -248.189496)
		(width 0.088646)
		(layer "In4.Cu")
		(net "M_C_CPU1_SB_CA<4>")
	)
	(segment
		(start 91.339416 -245.9863)
		(end 91.247214 -246.040148)
		(width 0.088646)
		(layer "In4.Cu")
		(net "M_C_CPU1_SB_CA<4>")
	)
	(segment
		(start 65.925954 -249.732292)
		(end 63.830962 -249.732292)
		(width 0.18288)
		(layer "In4.Cu")
		(net "M_C_CPU1_SB_CA<4>")
	)
	(segment
		(start 87.488268 -246.040148)
		(end 87.479378 -246.045228)
		(width 0.088646)
		(layer "In4.Cu")
		(net "M_C_CPU1_SB_CA<4>")
	)
	(segment
		(start 89.367614 -246.040148)
		(end 89.352882 -246.048784)
		(width 0.088646)
		(layer "In4.Cu")
		(net "M_C_CPU1_SB_CA<4>")
	)
	(segment
		(start 63.531496 -249.432826)
		(end 61.848492 -249.432826)
		(width 0.18288)
		(layer "In4.Cu")
		(net "M_C_CPU1_SB_CA<4>")
	)
	(segment
		(start 61.689488 -249.59183)
		(end 45.230542 -249.59183)
		(width 0.18288)
		(layer "In4.Cu")
		(net "M_C_CPU1_SB_CA<4>")
	)
	(segment
		(start 87.300816 -246.364506)
		(end 87.300816 -246.374412)
		(width 0.088646)
		(layer "In4.Cu")
		(net "M_C_CPU1_SB_CA<4>")
	)
	(segment
		(start 84.59089 -247.726962)
		(end 84.128356 -248.189496)
		(width 0.088646)
		(layer "In4.Cu")
		(net "M_C_CPU1_SB_CA<4>")
	)
	(segment
		(start 45.230542 -249.59183)
		(end 45.228764 -249.590052)
		(width 0.18288)
		(layer "In4.Cu")
		(net "M_C_CPU1_SB_CA<4>")
	)
	(segment
		(start 65.926208 -249.732038)
		(end 65.925954 -249.732292)
		(width 0.18288)
		(layer "In4.Cu")
		(net "M_C_CPU1_SB_CA<4>")
	)
	(segment
		(start 63.830962 -249.732292)
		(end 63.531496 -249.432826)
		(width 0.18288)
		(layer "In4.Cu")
		(net "M_C_CPU1_SB_CA<4>")
	)
	(segment
		(start 83.06435 -248.189496)
		(end 82.250534 -248.189496)
		(width 0.18288)
		(layer "In4.Cu")
		(net "M_C_CPU1_SB_CA<4>")
	)
	(arc
		(start 87.300816 -246.374412)
		(mid 87.222705 -246.651361)
		(end 87.018368 -246.853964)
		(width 0.088646)
		(layer "In4.Cu")
		(net "M_C_CPU1_SB_CA<4>")
	)
	(arc
		(start 87.479378 -246.045228)
		(mid 87.348464 -246.181588)
		(end 87.300816 -246.364506)
		(width 0.088646)
		(layer "In4.Cu")
		(net "M_C_CPU1_SB_CA<4>")
	)
	(arc
		(start 86.548468 -247.66778)
		(mid 86.265766 -247.743556)
		(end 85.983064 -247.66778)
		(width 0.088646)
		(layer "In4.Cu")
		(net "M_C_CPU1_SB_CA<4>")
	)
	(arc
		(start 91.247214 -246.040148)
		(mid 90.964512 -246.115924)
		(end 90.68181 -246.040148)
		(width 0.088646)
		(layer "In4.Cu")
		(net "M_C_CPU1_SB_CA<4>")
	)
	(arc
		(start 87.862664 -246.040148)
		(mid 87.675466 -245.990005)
		(end 87.488268 -246.040148)
		(width 0.088646)
		(layer "In4.Cu")
		(net "M_C_CPU1_SB_CA<4>")
	)
	(arc
		(start 85.608668 -247.66778)
		(mid 85.325966 -247.743556)
		(end 85.043264 -247.66778)
		(width 0.088646)
		(layer "In4.Cu")
		(net "M_C_CPU1_SB_CA<4>")
	)
	(arc
		(start 85.983064 -247.66778)
		(mid 85.795866 -247.617637)
		(end 85.608668 -247.66778)
		(width 0.088646)
		(layer "In4.Cu")
		(net "M_C_CPU1_SB_CA<4>")
	)
	(arc
		(start 88.80221 -246.040148)
		(mid 88.615012 -245.990005)
		(end 88.427814 -246.040148)
		(width 0.088646)
		(layer "In4.Cu")
		(net "M_C_CPU1_SB_CA<4>")
	)
	(arc
		(start 84.668868 -247.66778)
		(mid 84.627938 -247.694813)
		(end 84.59089 -247.726962)
		(width 0.088646)
		(layer "In4.Cu")
		(net "M_C_CPU1_SB_CA<4>")
	)
	(arc
		(start 86.830916 -247.188228)
		(mid 86.752805 -247.465177)
		(end 86.548468 -247.66778)
		(width 0.088646)
		(layer "In4.Cu")
		(net "M_C_CPU1_SB_CA<4>")
	)
	(arc
		(start 90.68181 -246.040148)
		(mid 90.494612 -245.990005)
		(end 90.307414 -246.040148)
		(width 0.088646)
		(layer "In4.Cu")
		(net "M_C_CPU1_SB_CA<4>")
	)
	(arc
		(start 91.904566 -245.55069)
		(mid 91.636023 -245.7867)
		(end 91.339416 -245.9863)
		(width 0.088646)
		(layer "In4.Cu")
		(net "M_C_CPU1_SB_CA<4>")
	)
	(arc
		(start 89.352882 -246.048784)
		(mid 89.076407 -246.116104)
		(end 88.80221 -246.040148)
		(width 0.088646)
		(layer "In4.Cu")
		(net "M_C_CPU1_SB_CA<4>")
	)
	(arc
		(start 87.009478 -246.859044)
		(mid 86.878564 -246.995404)
		(end 86.830916 -247.178322)
		(width 0.088646)
		(layer "In4.Cu")
		(net "M_C_CPU1_SB_CA<4>")
	)
	(arc
		(start 85.043264 -247.66778)
		(mid 84.856066 -247.617637)
		(end 84.668868 -247.66778)
		(width 0.088646)
		(layer "In4.Cu")
		(net "M_C_CPU1_SB_CA<4>")
	)
	(arc
		(start 88.4174 -246.046244)
		(mid 88.139222 -246.115967)
		(end 87.862664 -246.040148)
		(width 0.088646)
		(layer "In4.Cu")
		(net "M_C_CPU1_SB_CA<4>")
	)
	(arc
		(start 89.74201 -246.040148)
		(mid 89.554812 -245.990005)
		(end 89.367614 -246.040148)
		(width 0.088646)
		(layer "In4.Cu")
		(net "M_C_CPU1_SB_CA<4>")
	)
	(arc
		(start 90.292682 -246.048784)
		(mid 90.016207 -246.116104)
		(end 89.74201 -246.040148)
		(width 0.088646)
		(layer "In4.Cu")
		(net "M_C_CPU1_SB_CA<4>")
	)
	(segment
		(start 33.401762 -250.22429)
		(end 33.848294 -250.22429)
		(width 0.20066)
		(layer "F.Cu")
		(net "M_C_CPU1_SB_CA<3>")
	)
	(segment
		(start 32.666178 -250.292616)
		(end 32.666178 -250.140978)
		(width 0.20066)
		(layer "F.Cu")
		(net "M_C_CPU1_SB_CA<3>")
	)
	(segment
		(start 35.976814 -250.016772)
		(end 34.871914 -250.016772)
		(width 0.20066)
		(layer "F.Cu")
		(net "M_C_CPU1_SB_CA<3>")
	)
	(segment
		(start 29.29382 -250.455938)
		(end 29.647642 -250.455938)
		(width 0.20066)
		(layer "F.Cu")
		(net "M_C_CPU1_SB_CA<3>")
	)
	(segment
		(start 29.899864 -250.441714)
		(end 31.972758 -250.441714)
		(width 0.1016)
		(layer "F.Cu")
		(net "M_C_CPU1_SB_CA<3>")
	)
	(segment
		(start 32.51708 -250.441714)
		(end 32.666178 -250.292616)
		(width 0.20066)
		(layer "F.Cu")
		(net "M_C_CPU1_SB_CA<3>")
	)
	(segment
		(start 32.666178 -250.140978)
		(end 32.794702 -250.012454)
		(width 0.20066)
		(layer "F.Cu")
		(net "M_C_CPU1_SB_CA<3>")
	)
	(segment
		(start 93.314012 -246.900192)
		(end 93.314012 -246.364506)
		(width 0.20066)
		(layer "F.Cu")
		(net "M_C_CPU1_SB_CA<3>")
	)
	(segment
		(start 33.848294 -250.22429)
		(end 34.055812 -250.016772)
		(width 0.20066)
		(layer "F.Cu")
		(net "M_C_CPU1_SB_CA<3>")
	)
	(segment
		(start 32.794702 -250.012454)
		(end 33.189926 -250.012454)
		(width 0.20066)
		(layer "F.Cu")
		(net "M_C_CPU1_SB_CA<3>")
	)
	(segment
		(start 27.328114 -250.016772)
		(end 29.025342 -250.016772)
		(width 0.20066)
		(layer "F.Cu")
		(net "M_C_CPU1_SB_CA<3>")
	)
	(segment
		(start 34.055812 -250.016772)
		(end 34.871914 -250.016772)
		(width 0.20066)
		(layer "F.Cu")
		(net "M_C_CPU1_SB_CA<3>")
	)
	(segment
		(start 29.151326 -250.142756)
		(end 29.151326 -250.313444)
		(width 0.20066)
		(layer "F.Cu")
		(net "M_C_CPU1_SB_CA<3>")
	)
	(segment
		(start 29.151326 -250.313444)
		(end 29.29382 -250.455938)
		(width 0.20066)
		(layer "F.Cu")
		(net "M_C_CPU1_SB_CA<3>")
	)
	(segment
		(start 93.314266 -246.900446)
		(end 93.314012 -246.900192)
		(width 0.20066)
		(layer "F.Cu")
		(net "M_C_CPU1_SB_CA<3>")
	)
	(segment
		(start 29.661866 -250.441714)
		(end 29.899864 -250.441714)
		(width 0.101854)
		(layer "F.Cu")
		(net "M_C_CPU1_SB_CA<3>")
	)
	(segment
		(start 31.972758 -250.441714)
		(end 32.51708 -250.441714)
		(width 0.20066)
		(layer "F.Cu")
		(net "M_C_CPU1_SB_CA<3>")
	)
	(segment
		(start 29.647642 -250.455938)
		(end 29.661866 -250.441714)
		(width 0.101854)
		(layer "F.Cu")
		(net "M_C_CPU1_SB_CA<3>")
	)
	(segment
		(start 33.189926 -250.012454)
		(end 33.401762 -250.22429)
		(width 0.20066)
		(layer "F.Cu")
		(net "M_C_CPU1_SB_CA<3>")
	)
	(segment
		(start 29.025342 -250.016772)
		(end 29.151326 -250.142756)
		(width 0.20066)
		(layer "F.Cu")
		(net "M_C_CPU1_SB_CA<3>")
	)
	(segment
		(start 62.692026 -250.573032)
		(end 61.652404 -250.573032)
		(width 0.18288)
		(layer "In4.Cu")
		(net "M_C_CPU1_SB_CA<3>")
	)
	(segment
		(start 81.263744 -248.17959)
		(end 75.737466 -248.17959)
		(width 0.18288)
		(layer "In4.Cu")
		(net "M_C_CPU1_SB_CA<3>")
	)
	(segment
		(start 60.314078 -250.669806)
		(end 59.591194 -250.669806)
		(width 0.18288)
		(layer "In4.Cu")
		(net "M_C_CPU1_SB_CA<3>")
	)
	(segment
		(start 92.102178 -245.868952)
		(end 92.091764 -245.875048)
		(width 0.088646)
		(layer "In4.Cu")
		(net "M_C_CPU1_SB_CA<3>")
	)
	(segment
		(start 61.652404 -250.573032)
		(end 61.329824 -250.250452)
		(width 0.18288)
		(layer "In4.Cu")
		(net "M_C_CPU1_SB_CA<3>")
	)
	(segment
		(start 57.304686 -250.76658)
		(end 57.121806 -250.5837)
		(width 0.18288)
		(layer "In4.Cu")
		(net "M_C_CPU1_SB_CA<3>")
	)
	(segment
		(start 84.802218 -248.653046)
		(end 84.307934 -249.14733)
		(width 0.18288)
		(layer "In4.Cu")
		(net "M_C_CPU1_SB_CA<3>")
	)
	(segment
		(start 55.509922 -250.441714)
		(end 37.02812 -250.441714)
		(width 0.18288)
		(layer "In4.Cu")
		(net "M_C_CPU1_SB_CA<3>")
	)
	(segment
		(start 84.911184 -248.54408)
		(end 84.802218 -248.653046)
		(width 0.088646)
		(layer "In4.Cu")
		(net "M_C_CPU1_SB_CA<3>")
	)
	(segment
		(start 85.728302 -248.54408)
		(end 84.911184 -248.54408)
		(width 0.088646)
		(layer "In4.Cu")
		(net "M_C_CPU1_SB_CA<3>")
	)
	(segment
		(start 55.701184 -250.250452)
		(end 55.509922 -250.441714)
		(width 0.18288)
		(layer "In4.Cu")
		(net "M_C_CPU1_SB_CA<3>")
	)
	(segment
		(start 57.629806 -250.76658)
		(end 57.304686 -250.76658)
		(width 0.18288)
		(layer "In4.Cu")
		(net "M_C_CPU1_SB_CA<3>")
	)
	(segment
		(start 85.86597 -248.406412)
		(end 85.728302 -248.54408)
		(width 0.088646)
		(layer "In4.Cu")
		(net "M_C_CPU1_SB_CA<3>")
	)
	(segment
		(start 56.938926 -250.250452)
		(end 55.701184 -250.250452)
		(width 0.18288)
		(layer "In4.Cu")
		(net "M_C_CPU1_SB_CA<3>")
	)
	(segment
		(start 62.852046 -250.100846)
		(end 62.852046 -250.413012)
		(width 0.18288)
		(layer "In4.Cu")
		(net "M_C_CPU1_SB_CA<3>")
	)
	(segment
		(start 59.591194 -250.669806)
		(end 59.17184 -250.250452)
		(width 0.18288)
		(layer "In4.Cu")
		(net "M_C_CPU1_SB_CA<3>")
	)
	(segment
		(start 62.852046 -250.413012)
		(end 62.692026 -250.573032)
		(width 0.18288)
		(layer "In4.Cu")
		(net "M_C_CPU1_SB_CA<3>")
	)
	(segment
		(start 37.02812 -250.441714)
		(end 36.419536 -249.83313)
		(width 0.18288)
		(layer "In4.Cu")
		(net "M_C_CPU1_SB_CA<3>")
	)
	(segment
		(start 36.419536 -249.83313)
		(end 36.160456 -249.83313)
		(width 0.18288)
		(layer "In4.Cu")
		(net "M_C_CPU1_SB_CA<3>")
	)
	(segment
		(start 63.012066 -249.940826)
		(end 62.852046 -250.100846)
		(width 0.18288)
		(layer "In4.Cu")
		(net "M_C_CPU1_SB_CA<3>")
	)
	(segment
		(start 89.367614 -246.688864)
		(end 89.352882 -246.680228)
		(width 0.088646)
		(layer "In4.Cu")
		(net "M_C_CPU1_SB_CA<3>")
	)
	(segment
		(start 66.355976 -250.316238)
		(end 65.926208 -250.316238)
		(width 0.18288)
		(layer "In4.Cu")
		(net "M_C_CPU1_SB_CA<3>")
	)
	(segment
		(start 82.231484 -249.14733)
		(end 81.263744 -248.17959)
		(width 0.18288)
		(layer "In4.Cu")
		(net "M_C_CPU1_SB_CA<3>")
	)
	(segment
		(start 65.926208 -250.316238)
		(end 65.925954 -250.316492)
		(width 0.18288)
		(layer "In4.Cu")
		(net "M_C_CPU1_SB_CA<3>")
	)
	(segment
		(start 67.184016 -250.59767)
		(end 67.023996 -250.75769)
		(width 0.18288)
		(layer "In4.Cu")
		(net "M_C_CPU1_SB_CA<3>")
	)
	(segment
		(start 60.733432 -250.250452)
		(end 60.314078 -250.669806)
		(width 0.18288)
		(layer "In4.Cu")
		(net "M_C_CPU1_SB_CA<3>")
	)
	(segment
		(start 57.121806 -250.5837)
		(end 57.121806 -250.433332)
		(width 0.18288)
		(layer "In4.Cu")
		(net "M_C_CPU1_SB_CA<3>")
	)
	(segment
		(start 87.110316 -247.982232)
		(end 87.110316 -247.992138)
		(width 0.088646)
		(layer "In4.Cu")
		(net "M_C_CPU1_SB_CA<3>")
	)
	(segment
		(start 91.247214 -246.688864)
		(end 91.232482 -246.680228)
		(width 0.088646)
		(layer "In4.Cu")
		(net "M_C_CPU1_SB_CA<3>")
	)
	(segment
		(start 67.023996 -250.75769)
		(end 66.797428 -250.75769)
		(width 0.18288)
		(layer "In4.Cu")
		(net "M_C_CPU1_SB_CA<3>")
	)
	(segment
		(start 67.344036 -250.316238)
		(end 67.184016 -250.476258)
		(width 0.18288)
		(layer "In4.Cu")
		(net "M_C_CPU1_SB_CA<3>")
	)
	(segment
		(start 87.580216 -247.168416)
		(end 87.580216 -247.178322)
		(width 0.088646)
		(layer "In4.Cu")
		(net "M_C_CPU1_SB_CA<3>")
	)
	(segment
		(start 84.307934 -249.14733)
		(end 82.231484 -249.14733)
		(width 0.18288)
		(layer "In4.Cu")
		(net "M_C_CPU1_SB_CA<3>")
	)
	(segment
		(start 92.091764 -245.875048)
		(end 92.085668 -245.878604)
		(width 0.088646)
		(layer "In4.Cu")
		(net "M_C_CPU1_SB_CA<3>")
	)
	(segment
		(start 57.812686 -250.5837)
		(end 57.629806 -250.76658)
		(width 0.18288)
		(layer "In4.Cu")
		(net "M_C_CPU1_SB_CA<3>")
	)
	(segment
		(start 36.160456 -249.83313)
		(end 35.976814 -250.016772)
		(width 0.18288)
		(layer "In4.Cu")
		(net "M_C_CPU1_SB_CA<3>")
	)
	(segment
		(start 67.184016 -250.476258)
		(end 67.184016 -250.59767)
		(width 0.18288)
		(layer "In4.Cu")
		(net "M_C_CPU1_SB_CA<3>")
	)
	(segment
		(start 75.737466 -248.17959)
		(end 73.600818 -250.316238)
		(width 0.18288)
		(layer "In4.Cu")
		(net "M_C_CPU1_SB_CA<3>")
	)
	(segment
		(start 93.001338 -246.364506)
		(end 92.935806 -246.298974)
		(width 0.088646)
		(layer "In4.Cu")
		(net "M_C_CPU1_SB_CA<3>")
	)
	(segment
		(start 57.121806 -250.433332)
		(end 56.938926 -250.250452)
		(width 0.18288)
		(layer "In4.Cu")
		(net "M_C_CPU1_SB_CA<3>")
	)
	(segment
		(start 73.600818 -250.316238)
		(end 67.344036 -250.316238)
		(width 0.18288)
		(layer "In4.Cu")
		(net "M_C_CPU1_SB_CA<3>")
	)
	(segment
		(start 86.931754 -248.311416)
		(end 86.922864 -248.316496)
		(width 0.088646)
		(layer "In4.Cu")
		(net "M_C_CPU1_SB_CA<3>")
	)
	(segment
		(start 57.995566 -250.250452)
		(end 57.812686 -250.433332)
		(width 0.18288)
		(layer "In4.Cu")
		(net "M_C_CPU1_SB_CA<3>")
	)
	(segment
		(start 87.401654 -247.4976)
		(end 87.392764 -247.50268)
		(width 0.088646)
		(layer "In4.Cu")
		(net "M_C_CPU1_SB_CA<3>")
	)
	(segment
		(start 57.812686 -250.433332)
		(end 57.812686 -250.5837)
		(width 0.18288)
		(layer "In4.Cu")
		(net "M_C_CPU1_SB_CA<3>")
	)
	(segment
		(start 91.6305 -246.683784)
		(end 91.62161 -246.688864)
		(width 0.088646)
		(layer "In4.Cu")
		(net "M_C_CPU1_SB_CA<3>")
	)
	(segment
		(start 93.314012 -246.364506)
		(end 93.001338 -246.364506)
		(width 0.088646)
		(layer "In4.Cu")
		(net "M_C_CPU1_SB_CA<3>")
	)
	(segment
		(start 63.332106 -249.940826)
		(end 63.012066 -249.940826)
		(width 0.18288)
		(layer "In4.Cu")
		(net "M_C_CPU1_SB_CA<3>")
	)
	(segment
		(start 88.427814 -246.688864)
		(end 88.4174 -246.682768)
		(width 0.088646)
		(layer "In4.Cu")
		(net "M_C_CPU1_SB_CA<3>")
	)
	(segment
		(start 66.797428 -250.75769)
		(end 66.355976 -250.316238)
		(width 0.18288)
		(layer "In4.Cu")
		(net "M_C_CPU1_SB_CA<3>")
	)
	(segment
		(start 59.17184 -250.250452)
		(end 57.995566 -250.250452)
		(width 0.18288)
		(layer "In4.Cu")
		(net "M_C_CPU1_SB_CA<3>")
	)
	(segment
		(start 61.329824 -250.250452)
		(end 60.733432 -250.250452)
		(width 0.18288)
		(layer "In4.Cu")
		(net "M_C_CPU1_SB_CA<3>")
	)
	(segment
		(start 63.707772 -250.316492)
		(end 63.332106 -249.940826)
		(width 0.18288)
		(layer "In4.Cu")
		(net "M_C_CPU1_SB_CA<3>")
	)
	(segment
		(start 65.925954 -250.316492)
		(end 63.707772 -250.316492)
		(width 0.18288)
		(layer "In4.Cu")
		(net "M_C_CPU1_SB_CA<3>")
	)
	(arc
		(start 92.656914 -245.875048)
		(mid 92.380355 -245.799305)
		(end 92.102178 -245.868952)
		(width 0.088646)
		(layer "In4.Cu")
		(net "M_C_CPU1_SB_CA<3>")
	)
	(arc
		(start 90.68181 -246.688864)
		(mid 90.494612 -246.739007)
		(end 90.307414 -246.688864)
		(width 0.088646)
		(layer "In4.Cu")
		(net "M_C_CPU1_SB_CA<3>")
	)
	(arc
		(start 87.110316 -247.992138)
		(mid 87.062637 -248.175038)
		(end 86.931754 -248.311416)
		(width 0.088646)
		(layer "In4.Cu")
		(net "M_C_CPU1_SB_CA<3>")
	)
	(arc
		(start 89.352882 -246.680228)
		(mid 89.076407 -246.612908)
		(end 88.80221 -246.688864)
		(width 0.088646)
		(layer "In4.Cu")
		(net "M_C_CPU1_SB_CA<3>")
	)
	(arc
		(start 88.80221 -246.688864)
		(mid 88.615012 -246.739007)
		(end 88.427814 -246.688864)
		(width 0.088646)
		(layer "In4.Cu")
		(net "M_C_CPU1_SB_CA<3>")
	)
	(arc
		(start 86.922864 -248.316496)
		(mid 86.735666 -248.366639)
		(end 86.548468 -248.316496)
		(width 0.088646)
		(layer "In4.Cu")
		(net "M_C_CPU1_SB_CA<3>")
	)
	(arc
		(start 86.548468 -248.316496)
		(mid 86.191945 -248.245593)
		(end 85.86597 -248.406412)
		(width 0.088646)
		(layer "In4.Cu")
		(net "M_C_CPU1_SB_CA<3>")
	)
	(arc
		(start 92.085668 -245.878604)
		(mid 91.883081 -246.084955)
		(end 91.809062 -246.364506)
		(width 0.088646)
		(layer "In4.Cu")
		(net "M_C_CPU1_SB_CA<3>")
	)
	(arc
		(start 87.580216 -247.178322)
		(mid 87.532537 -247.361222)
		(end 87.401654 -247.4976)
		(width 0.088646)
		(layer "In4.Cu")
		(net "M_C_CPU1_SB_CA<3>")
	)
	(arc
		(start 91.809062 -246.364506)
		(mid 91.761383 -246.547406)
		(end 91.6305 -246.683784)
		(width 0.088646)
		(layer "In4.Cu")
		(net "M_C_CPU1_SB_CA<3>")
	)
	(arc
		(start 87.862664 -246.688864)
		(mid 87.658329 -246.891469)
		(end 87.580216 -247.168416)
		(width 0.088646)
		(layer "In4.Cu")
		(net "M_C_CPU1_SB_CA<3>")
	)
	(arc
		(start 88.4174 -246.682768)
		(mid 88.139222 -246.613045)
		(end 87.862664 -246.688864)
		(width 0.088646)
		(layer "In4.Cu")
		(net "M_C_CPU1_SB_CA<3>")
	)
	(arc
		(start 90.307414 -246.688864)
		(mid 90.024712 -246.613088)
		(end 89.74201 -246.688864)
		(width 0.088646)
		(layer "In4.Cu")
		(net "M_C_CPU1_SB_CA<3>")
	)
	(arc
		(start 91.62161 -246.688864)
		(mid 91.434412 -246.739007)
		(end 91.247214 -246.688864)
		(width 0.088646)
		(layer "In4.Cu")
		(net "M_C_CPU1_SB_CA<3>")
	)
	(arc
		(start 89.74201 -246.688864)
		(mid 89.554812 -246.739007)
		(end 89.367614 -246.688864)
		(width 0.088646)
		(layer "In4.Cu")
		(net "M_C_CPU1_SB_CA<3>")
	)
	(arc
		(start 91.232482 -246.680228)
		(mid 90.956007 -246.612908)
		(end 90.68181 -246.688864)
		(width 0.088646)
		(layer "In4.Cu")
		(net "M_C_CPU1_SB_CA<3>")
	)
	(arc
		(start 87.392764 -247.50268)
		(mid 87.188429 -247.705285)
		(end 87.110316 -247.982232)
		(width 0.088646)
		(layer "In4.Cu")
		(net "M_C_CPU1_SB_CA<3>")
	)
	(arc
		(start 92.935806 -246.298974)
		(mid 92.846632 -246.053932)
		(end 92.656914 -245.875048)
		(width 0.088646)
		(layer "In4.Cu")
		(net "M_C_CPU1_SB_CA<3>")
	)
	(segment
		(start 29.13253 -250.866656)
		(end 30.771846 -250.866656)
		(width 0.20066)
		(layer "F.Cu")
		(net "M_C_CPU1_SB_CA<2>")
	)
	(segment
		(start 92.374466 -246.900446)
		(end 92.374212 -246.900192)
		(width 0.20066)
		(layer "F.Cu")
		(net "M_C_CPU1_SB_CA<2>")
	)
	(segment
		(start 28.707588 -250.441714)
		(end 29.13253 -250.866656)
		(width 0.20066)
		(layer "F.Cu")
		(net "M_C_CPU1_SB_CA<2>")
	)
	(segment
		(start 26.2128 -250.441714)
		(end 28.198318 -250.441714)
		(width 0.1016)
		(layer "F.Cu")
		(net "M_C_CPU1_SB_CA<2>")
	)
	(segment
		(start 26.20391 -250.432824)
		(end 26.2128 -250.441714)
		(width 0.1016)
		(layer "F.Cu")
		(net "M_C_CPU1_SB_CA<2>")
	)
	(segment
		(start 92.374212 -246.900192)
		(end 92.374212 -246.364506)
		(width 0.20066)
		(layer "F.Cu")
		(net "M_C_CPU1_SB_CA<2>")
	)
	(segment
		(start 25.432512 -250.923552)
		(end 25.432512 -250.595384)
		(width 0.20066)
		(layer "F.Cu")
		(net "M_C_CPU1_SB_CA<2>")
	)
	(segment
		(start 28.198318 -250.441714)
		(end 28.529026 -250.441714)
		(width 0.101854)
		(layer "F.Cu")
		(net "M_C_CPU1_SB_CA<2>")
	)
	(segment
		(start 24.562308 -250.866656)
		(end 24.773636 -251.077984)
		(width 0.20066)
		(layer "F.Cu")
		(net "M_C_CPU1_SB_CA<2>")
	)
	(segment
		(start 24.773636 -251.077984)
		(end 25.27808 -251.077984)
		(width 0.20066)
		(layer "F.Cu")
		(net "M_C_CPU1_SB_CA<2>")
	)
	(segment
		(start 25.27808 -251.077984)
		(end 25.432512 -250.923552)
		(width 0.20066)
		(layer "F.Cu")
		(net "M_C_CPU1_SB_CA<2>")
	)
	(segment
		(start 28.529026 -250.441714)
		(end 28.707588 -250.441714)
		(width 0.20066)
		(layer "F.Cu")
		(net "M_C_CPU1_SB_CA<2>")
	)
	(segment
		(start 23.228046 -250.866656)
		(end 24.562308 -250.866656)
		(width 0.20066)
		(layer "F.Cu")
		(net "M_C_CPU1_SB_CA<2>")
	)
	(segment
		(start 25.595072 -250.432824)
		(end 26.20391 -250.432824)
		(width 0.20066)
		(layer "F.Cu")
		(net "M_C_CPU1_SB_CA<2>")
	)
	(segment
		(start 31.876746 -250.866656)
		(end 30.771846 -250.866656)
		(width 0.20066)
		(layer "F.Cu")
		(net "M_C_CPU1_SB_CA<2>")
	)
	(segment
		(start 25.432512 -250.595384)
		(end 25.595072 -250.432824)
		(width 0.20066)
		(layer "F.Cu")
		(net "M_C_CPU1_SB_CA<2>")
	)
	(segment
		(start 55.814722 -251.600208)
		(end 55.506366 -251.291852)
		(width 0.18288)
		(layer "In4.Cu")
		(net "M_C_CPU1_SB_CA<2>")
	)
	(segment
		(start 61.598048 -251.291852)
		(end 57.887362 -251.291852)
		(width 0.18288)
		(layer "In4.Cu")
		(net "M_C_CPU1_SB_CA<2>")
	)
	(segment
		(start 57.196482 -251.600208)
		(end 56.888126 -251.291852)
		(width 0.18288)
		(layer "In4.Cu")
		(net "M_C_CPU1_SB_CA<2>")
	)
	(segment
		(start 91.999562 -246.364506)
		(end 91.999562 -246.374412)
		(width 0.088646)
		(layer "In4.Cu")
		(net "M_C_CPU1_SB_CA<2>")
	)
	(segment
		(start 37.147754 -251.291852)
		(end 36.297616 -250.441714)
		(width 0.18288)
		(layer "In4.Cu")
		(net "M_C_CPU1_SB_CA<2>")
	)
	(segment
		(start 34.976816 -250.441714)
		(end 33.812734 -251.605796)
		(width 0.18288)
		(layer "In4.Cu")
		(net "M_C_CPU1_SB_CA<2>")
	)
	(segment
		(start 76.131928 -248.51487)
		(end 73.226168 -251.42063)
		(width 0.18288)
		(layer "In4.Cu")
		(net "M_C_CPU1_SB_CA<2>")
	)
	(segment
		(start 84.484718 -249.71121)
		(end 81.925668 -249.71121)
		(width 0.18288)
		(layer "In4.Cu")
		(net "M_C_CPU1_SB_CA<2>")
	)
	(segment
		(start 92.187014 -246.040148)
		(end 92.178124 -246.045228)
		(width 0.088646)
		(layer "In4.Cu")
		(net "M_C_CPU1_SB_CA<2>")
	)
	(segment
		(start 92.686886 -246.364506)
		(end 92.74429 -246.307102)
		(width 0.088646)
		(layer "In4.Cu")
		(net "M_C_CPU1_SB_CA<2>")
	)
	(segment
		(start 92.5703 -246.045228)
		(end 92.56141 -246.040148)
		(width 0.088646)
		(layer "In4.Cu")
		(net "M_C_CPU1_SB_CA<2>")
	)
	(segment
		(start 86.00059 -248.541032)
		(end 85.730842 -248.81078)
		(width 0.088646)
		(layer "In4.Cu")
		(net "M_C_CPU1_SB_CA<2>")
	)
	(segment
		(start 90.222324 -246.86006)
		(end 90.21191 -246.853964)
		(width 0.088646)
		(layer "In4.Cu")
		(net "M_C_CPU1_SB_CA<2>")
	)
	(segment
		(start 65.926208 -251.42063)
		(end 65.925954 -251.420884)
		(width 0.18288)
		(layer "In4.Cu")
		(net "M_C_CPU1_SB_CA<2>")
	)
	(segment
		(start 85.17255 -249.023378)
		(end 84.484718 -249.71121)
		(width 0.18288)
		(layer "In4.Cu")
		(net "M_C_CPU1_SB_CA<2>")
	)
	(segment
		(start 32.615886 -251.605796)
		(end 31.876746 -250.866656)
		(width 0.18288)
		(layer "In4.Cu")
		(net "M_C_CPU1_SB_CA<2>")
	)
	(segment
		(start 91.162378 -246.86006)
		(end 91.151964 -246.853964)
		(width 0.088646)
		(layer "In4.Cu")
		(net "M_C_CPU1_SB_CA<2>")
	)
	(segment
		(start 63.461392 -251.420884)
		(end 63.149734 -251.109226)
		(width 0.18288)
		(layer "In4.Cu")
		(net "M_C_CPU1_SB_CA<2>")
	)
	(segment
		(start 92.374212 -246.364506)
		(end 92.686886 -246.364506)
		(width 0.088646)
		(layer "In4.Cu")
		(net "M_C_CPU1_SB_CA<2>")
	)
	(segment
		(start 65.925954 -251.420884)
		(end 63.461392 -251.420884)
		(width 0.18288)
		(layer "In4.Cu")
		(net "M_C_CPU1_SB_CA<2>")
	)
	(segment
		(start 61.780674 -251.109226)
		(end 61.598048 -251.291852)
		(width 0.18288)
		(layer "In4.Cu")
		(net "M_C_CPU1_SB_CA<2>")
	)
	(segment
		(start 88.347296 -246.8626)
		(end 88.332564 -246.853964)
		(width 0.088646)
		(layer "In4.Cu")
		(net "M_C_CPU1_SB_CA<2>")
	)
	(segment
		(start 63.149734 -251.109226)
		(end 61.780674 -251.109226)
		(width 0.18288)
		(layer "In4.Cu")
		(net "M_C_CPU1_SB_CA<2>")
	)
	(segment
		(start 85.730842 -248.81078)
		(end 85.385148 -248.81078)
		(width 0.088646)
		(layer "In4.Cu")
		(net "M_C_CPU1_SB_CA<2>")
	)
	(segment
		(start 87.300816 -247.992138)
		(end 87.300816 -248.01068)
		(width 0.088646)
		(layer "In4.Cu")
		(net "M_C_CPU1_SB_CA<2>")
	)
	(segment
		(start 56.197246 -251.600208)
		(end 55.814722 -251.600208)
		(width 0.18288)
		(layer "In4.Cu")
		(net "M_C_CPU1_SB_CA<2>")
	)
	(segment
		(start 87.958168 -246.853964)
		(end 87.949278 -246.859044)
		(width 0.088646)
		(layer "In4.Cu")
		(net "M_C_CPU1_SB_CA<2>")
	)
	(segment
		(start 89.282778 -246.86006)
		(end 89.272364 -246.853964)
		(width 0.088646)
		(layer "In4.Cu")
		(net "M_C_CPU1_SB_CA<2>")
	)
	(segment
		(start 56.888126 -251.291852)
		(end 56.505602 -251.291852)
		(width 0.18288)
		(layer "In4.Cu")
		(net "M_C_CPU1_SB_CA<2>")
	)
	(segment
		(start 81.925668 -249.71121)
		(end 80.729328 -248.51487)
		(width 0.18288)
		(layer "In4.Cu")
		(net "M_C_CPU1_SB_CA<2>")
	)
	(segment
		(start 87.770716 -247.178322)
		(end 87.770716 -247.188228)
		(width 0.088646)
		(layer "In4.Cu")
		(net "M_C_CPU1_SB_CA<2>")
	)
	(segment
		(start 73.226168 -251.42063)
		(end 65.926208 -251.42063)
		(width 0.18288)
		(layer "In4.Cu")
		(net "M_C_CPU1_SB_CA<2>")
	)
	(segment
		(start 33.812734 -251.605796)
		(end 32.615886 -251.605796)
		(width 0.18288)
		(layer "In4.Cu")
		(net "M_C_CPU1_SB_CA<2>")
	)
	(segment
		(start 36.297616 -250.441714)
		(end 34.976816 -250.441714)
		(width 0.18288)
		(layer "In4.Cu")
		(net "M_C_CPU1_SB_CA<2>")
	)
	(segment
		(start 55.506366 -251.291852)
		(end 37.147754 -251.291852)
		(width 0.18288)
		(layer "In4.Cu")
		(net "M_C_CPU1_SB_CA<2>")
	)
	(segment
		(start 57.887362 -251.291852)
		(end 57.579006 -251.600208)
		(width 0.18288)
		(layer "In4.Cu")
		(net "M_C_CPU1_SB_CA<2>")
	)
	(segment
		(start 80.729328 -248.51487)
		(end 76.131928 -248.51487)
		(width 0.18288)
		(layer "In4.Cu")
		(net "M_C_CPU1_SB_CA<2>")
	)
	(segment
		(start 57.579006 -251.600208)
		(end 57.196482 -251.600208)
		(width 0.18288)
		(layer "In4.Cu")
		(net "M_C_CPU1_SB_CA<2>")
	)
	(segment
		(start 87.488268 -247.66778)
		(end 87.479378 -247.67286)
		(width 0.088646)
		(layer "In4.Cu")
		(net "M_C_CPU1_SB_CA<2>")
	)
	(segment
		(start 56.505602 -251.291852)
		(end 56.197246 -251.600208)
		(width 0.18288)
		(layer "In4.Cu")
		(net "M_C_CPU1_SB_CA<2>")
	)
	(segment
		(start 85.385148 -248.81078)
		(end 85.17255 -249.023378)
		(width 0.088646)
		(layer "In4.Cu")
		(net "M_C_CPU1_SB_CA<2>")
	)
	(arc
		(start 90.777568 -246.853964)
		(mid 90.500755 -246.929834)
		(end 90.222324 -246.86006)
		(width 0.088646)
		(layer "In4.Cu")
		(net "M_C_CPU1_SB_CA<2>")
	)
	(arc
		(start 87.479378 -247.67286)
		(mid 87.348464 -247.80922)
		(end 87.300816 -247.992138)
		(width 0.088646)
		(layer "In4.Cu")
		(net "M_C_CPU1_SB_CA<2>")
	)
	(arc
		(start 87.300816 -248.01068)
		(mid 87.220654 -248.282869)
		(end 87.018368 -248.48185)
		(width 0.088646)
		(layer "In4.Cu")
		(net "M_C_CPU1_SB_CA<2>")
	)
	(arc
		(start 89.837514 -246.853964)
		(mid 89.560955 -246.929707)
		(end 89.282778 -246.86006)
		(width 0.088646)
		(layer "In4.Cu")
		(net "M_C_CPU1_SB_CA<2>")
	)
	(arc
		(start 91.151964 -246.853964)
		(mid 90.964766 -246.803821)
		(end 90.777568 -246.853964)
		(width 0.088646)
		(layer "In4.Cu")
		(net "M_C_CPU1_SB_CA<2>")
	)
	(arc
		(start 90.21191 -246.853964)
		(mid 90.024712 -246.803821)
		(end 89.837514 -246.853964)
		(width 0.088646)
		(layer "In4.Cu")
		(net "M_C_CPU1_SB_CA<2>")
	)
	(arc
		(start 92.56141 -246.040148)
		(mid 92.374212 -245.990005)
		(end 92.187014 -246.040148)
		(width 0.088646)
		(layer "In4.Cu")
		(net "M_C_CPU1_SB_CA<2>")
	)
	(arc
		(start 86.452964 -248.48185)
		(mid 86.265766 -248.431707)
		(end 86.078568 -248.48185)
		(width 0.088646)
		(layer "In4.Cu")
		(net "M_C_CPU1_SB_CA<2>")
	)
	(arc
		(start 87.770716 -247.188228)
		(mid 87.692605 -247.465177)
		(end 87.488268 -247.66778)
		(width 0.088646)
		(layer "In4.Cu")
		(net "M_C_CPU1_SB_CA<2>")
	)
	(arc
		(start 91.717114 -246.853964)
		(mid 91.440555 -246.929707)
		(end 91.162378 -246.86006)
		(width 0.088646)
		(layer "In4.Cu")
		(net "M_C_CPU1_SB_CA<2>")
	)
	(arc
		(start 88.897968 -246.853964)
		(mid 88.623769 -246.929799)
		(end 88.347296 -246.8626)
		(width 0.088646)
		(layer "In4.Cu")
		(net "M_C_CPU1_SB_CA<2>")
	)
	(arc
		(start 91.999562 -246.374412)
		(mid 91.921451 -246.651361)
		(end 91.717114 -246.853964)
		(width 0.088646)
		(layer "In4.Cu")
		(net "M_C_CPU1_SB_CA<2>")
	)
	(arc
		(start 87.949278 -246.859044)
		(mid 87.818364 -246.995404)
		(end 87.770716 -247.178322)
		(width 0.088646)
		(layer "In4.Cu")
		(net "M_C_CPU1_SB_CA<2>")
	)
	(arc
		(start 89.272364 -246.853964)
		(mid 89.085166 -246.803821)
		(end 88.897968 -246.853964)
		(width 0.088646)
		(layer "In4.Cu")
		(net "M_C_CPU1_SB_CA<2>")
	)
	(arc
		(start 92.178124 -246.045228)
		(mid 92.04721 -246.181588)
		(end 91.999562 -246.364506)
		(width 0.088646)
		(layer "In4.Cu")
		(net "M_C_CPU1_SB_CA<2>")
	)
	(arc
		(start 92.74429 -246.307102)
		(mid 92.686134 -246.156989)
		(end 92.5703 -246.045228)
		(width 0.088646)
		(layer "In4.Cu")
		(net "M_C_CPU1_SB_CA<2>")
	)
	(arc
		(start 87.018368 -248.48185)
		(mid 86.735666 -248.557592)
		(end 86.452964 -248.48185)
		(width 0.088646)
		(layer "In4.Cu")
		(net "M_C_CPU1_SB_CA<2>")
	)
	(arc
		(start 88.332564 -246.853964)
		(mid 88.145366 -246.803821)
		(end 87.958168 -246.853964)
		(width 0.088646)
		(layer "In4.Cu")
		(net "M_C_CPU1_SB_CA<2>")
	)
	(arc
		(start 86.078568 -248.48185)
		(mid 86.037638 -248.508883)
		(end 86.00059 -248.541032)
		(width 0.088646)
		(layer "In4.Cu")
		(net "M_C_CPU1_SB_CA<2>")
	)
	(segment
		(start 32.51708 -252.141736)
		(end 32.666178 -251.992638)
		(width 0.20066)
		(layer "F.Cu")
		(net "M_C_CPU1_SB_CA<1>")
	)
	(segment
		(start 33.848294 -251.924312)
		(end 34.055812 -251.716794)
		(width 0.20066)
		(layer "F.Cu")
		(net "M_C_CPU1_SB_CA<1>")
	)
	(segment
		(start 33.189926 -251.712476)
		(end 33.401762 -251.924312)
		(width 0.20066)
		(layer "F.Cu")
		(net "M_C_CPU1_SB_CA<1>")
	)
	(segment
		(start 35.976814 -251.716794)
		(end 34.871914 -251.716794)
		(width 0.20066)
		(layer "F.Cu")
		(net "M_C_CPU1_SB_CA<1>")
	)
	(segment
		(start 34.055812 -251.716794)
		(end 34.871914 -251.716794)
		(width 0.20066)
		(layer "F.Cu")
		(net "M_C_CPU1_SB_CA<1>")
	)
	(segment
		(start 29.151326 -252.013466)
		(end 29.29382 -252.15596)
		(width 0.20066)
		(layer "F.Cu")
		(net "M_C_CPU1_SB_CA<1>")
	)
	(segment
		(start 29.29382 -252.15596)
		(end 29.647642 -252.15596)
		(width 0.20066)
		(layer "F.Cu")
		(net "M_C_CPU1_SB_CA<1>")
	)
	(segment
		(start 29.025342 -251.716794)
		(end 29.151326 -251.842778)
		(width 0.20066)
		(layer "F.Cu")
		(net "M_C_CPU1_SB_CA<1>")
	)
	(segment
		(start 29.151326 -251.842778)
		(end 29.151326 -252.013466)
		(width 0.20066)
		(layer "F.Cu")
		(net "M_C_CPU1_SB_CA<1>")
	)
	(segment
		(start 32.666178 -251.992638)
		(end 32.666178 -251.841)
		(width 0.20066)
		(layer "F.Cu")
		(net "M_C_CPU1_SB_CA<1>")
	)
	(segment
		(start 32.666178 -251.841)
		(end 32.794702 -251.712476)
		(width 0.20066)
		(layer "F.Cu")
		(net "M_C_CPU1_SB_CA<1>")
	)
	(segment
		(start 32.794702 -251.712476)
		(end 33.189926 -251.712476)
		(width 0.20066)
		(layer "F.Cu")
		(net "M_C_CPU1_SB_CA<1>")
	)
	(segment
		(start 93.893894 -253.383796)
		(end 93.893894 -253.919482)
		(width 0.20066)
		(layer "F.Cu")
		(net "M_C_CPU1_SB_CA<1>")
	)
	(segment
		(start 93.893894 -253.919482)
		(end 93.894148 -253.919736)
		(width 0.20066)
		(layer "F.Cu")
		(net "M_C_CPU1_SB_CA<1>")
	)
	(segment
		(start 27.328114 -251.716794)
		(end 29.025342 -251.716794)
		(width 0.20066)
		(layer "F.Cu")
		(net "M_C_CPU1_SB_CA<1>")
	)
	(segment
		(start 29.661866 -252.141736)
		(end 29.899864 -252.141736)
		(width 0.101854)
		(layer "F.Cu")
		(net "M_C_CPU1_SB_CA<1>")
	)
	(segment
		(start 29.899864 -252.141736)
		(end 31.972758 -252.141736)
		(width 0.1016)
		(layer "F.Cu")
		(net "M_C_CPU1_SB_CA<1>")
	)
	(segment
		(start 33.401762 -251.924312)
		(end 33.848294 -251.924312)
		(width 0.20066)
		(layer "F.Cu")
		(net "M_C_CPU1_SB_CA<1>")
	)
	(segment
		(start 31.972758 -252.141736)
		(end 32.51708 -252.141736)
		(width 0.20066)
		(layer "F.Cu")
		(net "M_C_CPU1_SB_CA<1>")
	)
	(segment
		(start 29.647642 -252.15596)
		(end 29.661866 -252.141736)
		(width 0.101854)
		(layer "F.Cu")
		(net "M_C_CPU1_SB_CA<1>")
	)
	(segment
		(start 94.151958 -253.513336)
		(end 94.151958 -253.035562)
		(width 0.088646)
		(layer "In4.Cu")
		(net "M_C_CPU1_SB_CA<1>")
	)
	(segment
		(start 79.66329 -249.24131)
		(end 76.845668 -249.24131)
		(width 0.18288)
		(layer "In4.Cu")
		(net "M_C_CPU1_SB_CA<1>")
	)
	(segment
		(start 94.151958 -252.036834)
		(end 92.997274 -250.88215)
		(width 0.18288)
		(layer "In4.Cu")
		(net "M_C_CPU1_SB_CA<1>")
	)
	(segment
		(start 72.920606 -253.166372)
		(end 65.926208 -253.166372)
		(width 0.18288)
		(layer "In4.Cu")
		(net "M_C_CPU1_SB_CA<1>")
	)
	(segment
		(start 94.151958 -253.035562)
		(end 94.151958 -252.036834)
		(width 0.18288)
		(layer "In4.Cu")
		(net "M_C_CPU1_SB_CA<1>")
	)
	(segment
		(start 36.40328 -252.947424)
		(end 36.40328 -252.383544)
		(width 0.18288)
		(layer "In4.Cu")
		(net "M_C_CPU1_SB_CA<1>")
	)
	(segment
		(start 93.894148 -253.919736)
		(end 94.050612 -254.190754)
		(width 0.088646)
		(layer "In4.Cu")
		(net "M_C_CPU1_SB_CA<1>")
	)
	(segment
		(start 94.050612 -254.190754)
		(end 94.12859 -254.211582)
		(width 0.088646)
		(layer "In4.Cu")
		(net "M_C_CPU1_SB_CA<1>")
	)
	(segment
		(start 36.40328 -252.383544)
		(end 36.233354 -251.973334)
		(width 0.18288)
		(layer "In4.Cu")
		(net "M_C_CPU1_SB_CA<1>")
	)
	(segment
		(start 94.268544 -253.928372)
		(end 94.268544 -253.629922)
		(width 0.088646)
		(layer "In4.Cu")
		(net "M_C_CPU1_SB_CA<1>")
	)
	(segment
		(start 81.30413 -250.88215)
		(end 79.66329 -249.24131)
		(width 0.18288)
		(layer "In4.Cu")
		(net "M_C_CPU1_SB_CA<1>")
	)
	(segment
		(start 94.268544 -253.629922)
		(end 94.151958 -253.513336)
		(width 0.088646)
		(layer "In4.Cu")
		(net "M_C_CPU1_SB_CA<1>")
	)
	(segment
		(start 76.845668 -249.24131)
		(end 72.920606 -253.166372)
		(width 0.18288)
		(layer "In4.Cu")
		(net "M_C_CPU1_SB_CA<1>")
	)
	(segment
		(start 36.233354 -251.973334)
		(end 35.976814 -251.716794)
		(width 0.18288)
		(layer "In4.Cu")
		(net "M_C_CPU1_SB_CA<1>")
	)
	(segment
		(start 65.925954 -253.166626)
		(end 36.622482 -253.166626)
		(width 0.18288)
		(layer "In4.Cu")
		(net "M_C_CPU1_SB_CA<1>")
	)
	(segment
		(start 92.997274 -250.88215)
		(end 81.30413 -250.88215)
		(width 0.18288)
		(layer "In4.Cu")
		(net "M_C_CPU1_SB_CA<1>")
	)
	(segment
		(start 36.622482 -253.166626)
		(end 36.40328 -252.947424)
		(width 0.18288)
		(layer "In4.Cu")
		(net "M_C_CPU1_SB_CA<1>")
	)
	(segment
		(start 65.926208 -253.166372)
		(end 65.925954 -253.166626)
		(width 0.18288)
		(layer "In4.Cu")
		(net "M_C_CPU1_SB_CA<1>")
	)
	(arc
		(start 94.12859 -254.211582)
		(mid 94.229911 -254.085461)
		(end 94.268544 -253.928372)
		(width 0.088646)
		(layer "In4.Cu")
		(net "M_C_CPU1_SB_CA<1>")
	)
	(segment
		(start 28.529026 -252.141736)
		(end 28.707588 -252.141736)
		(width 0.20066)
		(layer "F.Cu")
		(net "M_C_CPU1_SB_CA<0>")
	)
	(segment
		(start 93.424248 -254.197612)
		(end 94.363794 -254.733552)
		(width 0.20066)
		(layer "F.Cu")
		(net "M_C_CPU1_SB_CA<0>")
	)
	(segment
		(start 28.198318 -252.141736)
		(end 28.529026 -252.141736)
		(width 0.101854)
		(layer "F.Cu")
		(net "M_C_CPU1_SB_CA<0>")
	)
	(segment
		(start 29.13253 -252.566678)
		(end 30.771846 -252.566678)
		(width 0.20066)
		(layer "F.Cu")
		(net "M_C_CPU1_SB_CA<0>")
	)
	(segment
		(start 25.27808 -252.778006)
		(end 25.432512 -252.623574)
		(width 0.20066)
		(layer "F.Cu")
		(net "M_C_CPU1_SB_CA<0>")
	)
	(segment
		(start 26.2128 -252.141736)
		(end 28.198318 -252.141736)
		(width 0.1016)
		(layer "F.Cu")
		(net "M_C_CPU1_SB_CA<0>")
	)
	(segment
		(start 25.595072 -252.132846)
		(end 26.20391 -252.132846)
		(width 0.20066)
		(layer "F.Cu")
		(net "M_C_CPU1_SB_CA<0>")
	)
	(segment
		(start 24.773636 -252.778006)
		(end 25.27808 -252.778006)
		(width 0.20066)
		(layer "F.Cu")
		(net "M_C_CPU1_SB_CA<0>")
	)
	(segment
		(start 25.432512 -252.623574)
		(end 25.432512 -252.295406)
		(width 0.20066)
		(layer "F.Cu")
		(net "M_C_CPU1_SB_CA<0>")
	)
	(segment
		(start 23.228046 -252.566678)
		(end 24.562308 -252.566678)
		(width 0.20066)
		(layer "F.Cu")
		(net "M_C_CPU1_SB_CA<0>")
	)
	(segment
		(start 25.432512 -252.295406)
		(end 25.595072 -252.132846)
		(width 0.20066)
		(layer "F.Cu")
		(net "M_C_CPU1_SB_CA<0>")
	)
	(segment
		(start 28.707588 -252.141736)
		(end 29.13253 -252.566678)
		(width 0.20066)
		(layer "F.Cu")
		(net "M_C_CPU1_SB_CA<0>")
	)
	(segment
		(start 24.562308 -252.566678)
		(end 24.773636 -252.778006)
		(width 0.20066)
		(layer "F.Cu")
		(net "M_C_CPU1_SB_CA<0>")
	)
	(segment
		(start 31.876746 -252.566678)
		(end 30.771846 -252.566678)
		(width 0.20066)
		(layer "F.Cu")
		(net "M_C_CPU1_SB_CA<0>")
	)
	(segment
		(start 26.20391 -252.132846)
		(end 26.2128 -252.141736)
		(width 0.1016)
		(layer "F.Cu")
		(net "M_C_CPU1_SB_CA<0>")
	)
	(segment
		(start 94.363794 -254.733552)
		(end 94.20733 -254.462534)
		(width 0.088646)
		(layer "In4.Cu")
		(net "M_C_CPU1_SB_CA<0>")
	)
	(segment
		(start 35.542474 -251.291852)
		(end 34.982912 -251.851414)
		(width 0.18288)
		(layer "In4.Cu")
		(net "M_C_CPU1_SB_CA<0>")
	)
	(segment
		(start 76.4667 -248.90095)
		(end 73.225914 -252.141736)
		(width 0.18288)
		(layer "In4.Cu")
		(net "M_C_CPU1_SB_CA<0>")
	)
	(segment
		(start 94.71406 -251.69876)
		(end 93.3831 -250.3678)
		(width 0.18288)
		(layer "In4.Cu")
		(net "M_C_CPU1_SB_CA<0>")
	)
	(segment
		(start 93.3831 -250.3678)
		(end 85.8901 -250.3678)
		(width 0.18288)
		(layer "In4.Cu")
		(net "M_C_CPU1_SB_CA<0>")
	)
	(segment
		(start 94.459298 -253.621032)
		(end 94.71406 -253.36627)
		(width 0.088646)
		(layer "In4.Cu")
		(net "M_C_CPU1_SB_CA<0>")
	)
	(segment
		(start 36.742116 -251.85243)
		(end 36.742116 -251.636784)
		(width 0.18288)
		(layer "In4.Cu")
		(net "M_C_CPU1_SB_CA<0>")
	)
	(segment
		(start 94.20733 -254.462534)
		(end 94.23146 -254.37338)
		(width 0.088646)
		(layer "In4.Cu")
		(net "M_C_CPU1_SB_CA<0>")
	)
	(segment
		(start 37.031422 -252.141736)
		(end 36.742116 -251.85243)
		(width 0.18288)
		(layer "In4.Cu")
		(net "M_C_CPU1_SB_CA<0>")
	)
	(segment
		(start 94.459298 -253.919736)
		(end 94.459298 -253.621032)
		(width 0.088646)
		(layer "In4.Cu")
		(net "M_C_CPU1_SB_CA<0>")
	)
	(segment
		(start 94.71406 -253.035562)
		(end 94.71406 -251.69876)
		(width 0.18288)
		(layer "In4.Cu")
		(net "M_C_CPU1_SB_CA<0>")
	)
	(segment
		(start 94.71406 -253.36627)
		(end 94.71406 -253.035562)
		(width 0.088646)
		(layer "In4.Cu")
		(net "M_C_CPU1_SB_CA<0>")
	)
	(segment
		(start 34.982912 -251.851414)
		(end 33.25622 -252.566678)
		(width 0.18288)
		(layer "In4.Cu")
		(net "M_C_CPU1_SB_CA<0>")
	)
	(segment
		(start 36.397184 -251.291852)
		(end 35.542474 -251.291852)
		(width 0.18288)
		(layer "In4.Cu")
		(net "M_C_CPU1_SB_CA<0>")
	)
	(segment
		(start 73.225914 -252.141736)
		(end 37.031422 -252.141736)
		(width 0.18288)
		(layer "In4.Cu")
		(net "M_C_CPU1_SB_CA<0>")
	)
	(segment
		(start 85.437726 -249.915426)
		(end 85.034882 -249.915426)
		(width 0.18288)
		(layer "In4.Cu")
		(net "M_C_CPU1_SB_CA<0>")
	)
	(segment
		(start 33.25622 -252.566678)
		(end 31.876746 -252.566678)
		(width 0.18288)
		(layer "In4.Cu")
		(net "M_C_CPU1_SB_CA<0>")
	)
	(segment
		(start 85.8901 -250.3678)
		(end 85.437726 -249.915426)
		(width 0.18288)
		(layer "In4.Cu")
		(net "M_C_CPU1_SB_CA<0>")
	)
	(segment
		(start 36.742116 -251.636784)
		(end 36.397184 -251.291852)
		(width 0.18288)
		(layer "In4.Cu")
		(net "M_C_CPU1_SB_CA<0>")
	)
	(segment
		(start 80.205834 -248.90095)
		(end 76.4667 -248.90095)
		(width 0.18288)
		(layer "In4.Cu")
		(net "M_C_CPU1_SB_CA<0>")
	)
	(segment
		(start 84.738718 -250.21159)
		(end 81.516474 -250.21159)
		(width 0.18288)
		(layer "In4.Cu")
		(net "M_C_CPU1_SB_CA<0>")
	)
	(segment
		(start 85.034882 -249.915426)
		(end 84.738718 -250.21159)
		(width 0.18288)
		(layer "In4.Cu")
		(net "M_C_CPU1_SB_CA<0>")
	)
	(segment
		(start 81.516474 -250.21159)
		(end 80.205834 -248.90095)
		(width 0.18288)
		(layer "In4.Cu")
		(net "M_C_CPU1_SB_CA<0>")
	)
	(arc
		(start 94.23146 -254.37338)
		(mid 94.399159 -254.173575)
		(end 94.459298 -253.919736)
		(width 0.088646)
		(layer "In4.Cu")
		(net "M_C_CPU1_SB_CA<0>")
	)
	(segment
		(start 95.773494 -253.919482)
		(end 95.773748 -253.919736)
		(width 0.20066)
		(layer "F.Cu")
		(net "M_C_CPU1_SA_RSP<1>")
	)
	(segment
		(start 95.773494 -253.383796)
		(end 95.773494 -253.919482)
		(width 0.20066)
		(layer "F.Cu")
		(net "M_C_CPU1_SA_RSP<1>")
	)
	(segment
		(start 30.771846 -244.066568)
		(end 31.876746 -244.066568)
		(width 0.20066)
		(layer "F.Cu")
		(net "M_C_CPU1_SA_RSP<1>")
	)
	(segment
		(start 44.339764 -248.793)
		(end 44.192952 -248.646188)
		(width 0.18288)
		(layer "In6.Cu")
		(net "M_C_CPU1_SA_RSP<1>")
	)
	(segment
		(start 76.289916 -254.489712)
		(end 75.385676 -254.115062)
		(width 0.18288)
		(layer "In6.Cu")
		(net "M_C_CPU1_SA_RSP<1>")
	)
	(segment
		(start 49.420526 -250.979686)
		(end 49.420526 -250.652026)
		(width 0.18288)
		(layer "In6.Cu")
		(net "M_C_CPU1_SA_RSP<1>")
	)
	(segment
		(start 55.694326 -252.076966)
		(end 55.366666 -252.404626)
		(width 0.18288)
		(layer "In6.Cu")
		(net "M_C_CPU1_SA_RSP<1>")
	)
	(segment
		(start 95.973138 -253.60249)
		(end 95.960692 -253.595378)
		(width 0.088646)
		(layer "In6.Cu")
		(net "M_C_CPU1_SA_RSP<1>")
	)
	(segment
		(start 63.899542 -251.964698)
		(end 63.162942 -252.701298)
		(width 0.18288)
		(layer "In6.Cu")
		(net "M_C_CPU1_SA_RSP<1>")
	)
	(segment
		(start 84.434934 -253.383034)
		(end 81.467452 -253.383034)
		(width 0.18288)
		(layer "In6.Cu")
		(net "M_C_CPU1_SA_RSP<1>")
	)
	(segment
		(start 42.608246 -248.829068)
		(end 42.608246 -249.164094)
		(width 0.18288)
		(layer "In6.Cu")
		(net "M_C_CPU1_SA_RSP<1>")
	)
	(segment
		(start 34.450782 -246.396002)
		(end 34.450782 -245.523512)
		(width 0.18288)
		(layer "In6.Cu")
		(net "M_C_CPU1_SA_RSP<1>")
	)
	(segment
		(start 68.848224 -254.115062)
		(end 64.457326 -252.296676)
		(width 0.18288)
		(layer "In6.Cu")
		(net "M_C_CPU1_SA_RSP<1>")
	)
	(segment
		(start 33.15081 -245.340632)
		(end 31.876746 -244.066568)
		(width 0.18288)
		(layer "In6.Cu")
		(net "M_C_CPU1_SA_RSP<1>")
	)
	(segment
		(start 76.502514 -254.57785)
		(end 76.29017 -254.489712)
		(width 0.18288)
		(layer "In6.Cu")
		(net "M_C_CPU1_SA_RSP<1>")
	)
	(segment
		(start 37.260022 -245.340632)
		(end 35.324542 -245.340632)
		(width 0.18288)
		(layer "In6.Cu")
		(net "M_C_CPU1_SA_RSP<1>")
	)
	(segment
		(start 95.035624 -253.604014)
		(end 95.020892 -253.595378)
		(width 0.088646)
		(layer "In6.Cu")
		(net "M_C_CPU1_SA_RSP<1>")
	)
	(segment
		(start 34.633662 -246.578882)
		(end 34.450782 -246.396002)
		(width 0.18288)
		(layer "In6.Cu")
		(net "M_C_CPU1_SA_RSP<1>")
	)
	(segment
		(start 94.176596 -254.409194)
		(end 94.161864 -254.41783)
		(width 0.088646)
		(layer "In6.Cu")
		(net "M_C_CPU1_SA_RSP<1>")
	)
	(segment
		(start 96.086676 -253.919736)
		(end 96.143826 -253.862586)
		(width 0.088646)
		(layer "In6.Cu")
		(net "M_C_CPU1_SA_RSP<1>")
	)
	(segment
		(start 46.17085 -248.793)
		(end 44.339764 -248.793)
		(width 0.18288)
		(layer "In6.Cu")
		(net "M_C_CPU1_SA_RSP<1>")
	)
	(segment
		(start 85.76691 -254.13589)
		(end 85.014562 -253.383034)
		(width 0.088646)
		(layer "In6.Cu")
		(net "M_C_CPU1_SA_RSP<1>")
	)
	(segment
		(start 85.014562 -253.383034)
		(end 84.434934 -253.383034)
		(width 0.088646)
		(layer "In6.Cu")
		(net "M_C_CPU1_SA_RSP<1>")
	)
	(segment
		(start 47.50943 -248.74093)
		(end 46.888146 -248.74093)
		(width 0.18288)
		(layer "In6.Cu")
		(net "M_C_CPU1_SA_RSP<1>")
	)
	(segment
		(start 40.426894 -248.646188)
		(end 39.511986 -247.73128)
		(width 0.18288)
		(layer "In6.Cu")
		(net "M_C_CPU1_SA_RSP<1>")
	)
	(segment
		(start 46.888146 -248.74093)
		(end 46.887384 -248.741692)
		(width 0.18288)
		(layer "In6.Cu")
		(net "M_C_CPU1_SA_RSP<1>")
	)
	(segment
		(start 49.420526 -250.652026)
		(end 47.50943 -248.74093)
		(width 0.18288)
		(layer "In6.Cu")
		(net "M_C_CPU1_SA_RSP<1>")
	)
	(segment
		(start 38.534848 -247.73128)
		(end 37.923724 -247.120156)
		(width 0.18288)
		(layer "In6.Cu")
		(net "M_C_CPU1_SA_RSP<1>")
	)
	(segment
		(start 78.582774 -254.57785)
		(end 76.502514 -254.57785)
		(width 0.18288)
		(layer "In6.Cu")
		(net "M_C_CPU1_SA_RSP<1>")
	)
	(segment
		(start 37.923724 -246.004334)
		(end 37.260022 -245.340632)
		(width 0.18288)
		(layer "In6.Cu")
		(net "M_C_CPU1_SA_RSP<1>")
	)
	(segment
		(start 41.734486 -248.646188)
		(end 40.426894 -248.646188)
		(width 0.18288)
		(layer "In6.Cu")
		(net "M_C_CPU1_SA_RSP<1>")
	)
	(segment
		(start 64.457326 -252.296676)
		(end 64.12611 -251.964698)
		(width 0.18288)
		(layer "In6.Cu")
		(net "M_C_CPU1_SA_RSP<1>")
	)
	(segment
		(start 35.324542 -245.340632)
		(end 35.141662 -245.523512)
		(width 0.18288)
		(layer "In6.Cu")
		(net "M_C_CPU1_SA_RSP<1>")
	)
	(segment
		(start 42.608246 -249.164094)
		(end 42.425366 -249.346974)
		(width 0.18288)
		(layer "In6.Cu")
		(net "M_C_CPU1_SA_RSP<1>")
	)
	(segment
		(start 64.12611 -251.964698)
		(end 63.899542 -251.964698)
		(width 0.18288)
		(layer "In6.Cu")
		(net "M_C_CPU1_SA_RSP<1>")
	)
	(segment
		(start 51.782726 -251.68225)
		(end 51.391566 -251.29109)
		(width 0.18288)
		(layer "In6.Cu")
		(net "M_C_CPU1_SA_RSP<1>")
	)
	(segment
		(start 92.296996 -254.409194)
		(end 92.286582 -254.41529)
		(width 0.088646)
		(layer "In6.Cu")
		(net "M_C_CPU1_SA_RSP<1>")
	)
	(segment
		(start 55.366666 -252.404626)
		(end 52.107846 -252.404626)
		(width 0.18288)
		(layer "In6.Cu")
		(net "M_C_CPU1_SA_RSP<1>")
	)
	(segment
		(start 42.425366 -249.346974)
		(end 42.100246 -249.346974)
		(width 0.18288)
		(layer "In6.Cu")
		(net "M_C_CPU1_SA_RSP<1>")
	)
	(segment
		(start 46.887384 -248.741692)
		(end 46.222158 -248.741692)
		(width 0.18288)
		(layer "In6.Cu")
		(net "M_C_CPU1_SA_RSP<1>")
	)
	(segment
		(start 44.192952 -248.646188)
		(end 42.791126 -248.646188)
		(width 0.18288)
		(layer "In6.Cu")
		(net "M_C_CPU1_SA_RSP<1>")
	)
	(segment
		(start 56.781446 -252.076966)
		(end 55.694326 -252.076966)
		(width 0.18288)
		(layer "In6.Cu")
		(net "M_C_CPU1_SA_RSP<1>")
	)
	(segment
		(start 41.917366 -248.829068)
		(end 41.734486 -248.646188)
		(width 0.18288)
		(layer "In6.Cu")
		(net "M_C_CPU1_SA_RSP<1>")
	)
	(segment
		(start 34.958782 -246.578882)
		(end 34.633662 -246.578882)
		(width 0.18288)
		(layer "In6.Cu")
		(net "M_C_CPU1_SA_RSP<1>")
	)
	(segment
		(start 57.405778 -252.701298)
		(end 56.781446 -252.076966)
		(width 0.18288)
		(layer "In6.Cu")
		(net "M_C_CPU1_SA_RSP<1>")
	)
	(segment
		(start 39.511986 -247.73128)
		(end 38.534848 -247.73128)
		(width 0.18288)
		(layer "In6.Cu")
		(net "M_C_CPU1_SA_RSP<1>")
	)
	(segment
		(start 76.29017 -254.489712)
		(end 76.289916 -254.489712)
		(width 0.18288)
		(layer "In6.Cu")
		(net "M_C_CPU1_SA_RSP<1>")
	)
	(segment
		(start 42.791126 -248.646188)
		(end 42.608246 -248.829068)
		(width 0.18288)
		(layer "In6.Cu")
		(net "M_C_CPU1_SA_RSP<1>")
	)
	(segment
		(start 81.467452 -253.383034)
		(end 78.582774 -254.57785)
		(width 0.18288)
		(layer "In6.Cu")
		(net "M_C_CPU1_SA_RSP<1>")
	)
	(segment
		(start 42.100246 -249.346974)
		(end 41.917366 -249.164094)
		(width 0.18288)
		(layer "In6.Cu")
		(net "M_C_CPU1_SA_RSP<1>")
	)
	(segment
		(start 51.391566 -251.29109)
		(end 49.73193 -251.29109)
		(width 0.18288)
		(layer "In6.Cu")
		(net "M_C_CPU1_SA_RSP<1>")
	)
	(segment
		(start 41.917366 -249.164094)
		(end 41.917366 -248.829068)
		(width 0.18288)
		(layer "In6.Cu")
		(net "M_C_CPU1_SA_RSP<1>")
	)
	(segment
		(start 95.773748 -253.919736)
		(end 96.086676 -253.919736)
		(width 0.088646)
		(layer "In6.Cu")
		(net "M_C_CPU1_SA_RSP<1>")
	)
	(segment
		(start 63.162942 -252.701298)
		(end 57.405778 -252.701298)
		(width 0.18288)
		(layer "In6.Cu")
		(net "M_C_CPU1_SA_RSP<1>")
	)
	(segment
		(start 34.450782 -245.523512)
		(end 34.267902 -245.340632)
		(width 0.18288)
		(layer "In6.Cu")
		(net "M_C_CPU1_SA_RSP<1>")
	)
	(segment
		(start 46.222158 -248.741692)
		(end 46.17085 -248.793)
		(width 0.18288)
		(layer "In6.Cu")
		(net "M_C_CPU1_SA_RSP<1>")
	)
	(segment
		(start 94.459298 -253.9111)
		(end 94.459298 -253.919736)
		(width 0.088646)
		(layer "In6.Cu")
		(net "M_C_CPU1_SA_RSP<1>")
	)
	(segment
		(start 52.107846 -252.404626)
		(end 51.782726 -252.079506)
		(width 0.18288)
		(layer "In6.Cu")
		(net "M_C_CPU1_SA_RSP<1>")
	)
	(segment
		(start 35.141662 -246.396002)
		(end 34.958782 -246.578882)
		(width 0.18288)
		(layer "In6.Cu")
		(net "M_C_CPU1_SA_RSP<1>")
	)
	(segment
		(start 37.923724 -247.120156)
		(end 37.923724 -246.004334)
		(width 0.18288)
		(layer "In6.Cu")
		(net "M_C_CPU1_SA_RSP<1>")
	)
	(segment
		(start 35.141662 -245.523512)
		(end 35.141662 -246.396002)
		(width 0.18288)
		(layer "In6.Cu")
		(net "M_C_CPU1_SA_RSP<1>")
	)
	(segment
		(start 51.782726 -252.079506)
		(end 51.782726 -251.68225)
		(width 0.18288)
		(layer "In6.Cu")
		(net "M_C_CPU1_SA_RSP<1>")
	)
	(segment
		(start 75.385676 -254.115062)
		(end 68.848224 -254.115062)
		(width 0.18288)
		(layer "In6.Cu")
		(net "M_C_CPU1_SA_RSP<1>")
	)
	(segment
		(start 49.73193 -251.29109)
		(end 49.420526 -250.979686)
		(width 0.18288)
		(layer "In6.Cu")
		(net "M_C_CPU1_SA_RSP<1>")
	)
	(segment
		(start 95.960692 -253.595378)
		(end 95.948754 -253.58852)
		(width 0.088646)
		(layer "In6.Cu")
		(net "M_C_CPU1_SA_RSP<1>")
	)
	(segment
		(start 94.182692 -254.405638)
		(end 94.176596 -254.409194)
		(width 0.088646)
		(layer "In6.Cu")
		(net "M_C_CPU1_SA_RSP<1>")
	)
	(segment
		(start 93.236796 -254.409194)
		(end 93.222064 -254.41783)
		(width 0.088646)
		(layer "In6.Cu")
		(net "M_C_CPU1_SA_RSP<1>")
	)
	(segment
		(start 34.267902 -245.340632)
		(end 33.15081 -245.340632)
		(width 0.18288)
		(layer "In6.Cu")
		(net "M_C_CPU1_SA_RSP<1>")
	)
	(segment
		(start 91.35745 -254.409194)
		(end 91.347036 -254.41529)
		(width 0.088646)
		(layer "In6.Cu")
		(net "M_C_CPU1_SA_RSP<1>")
	)
	(arc
		(start 87.032592 -254.409194)
		(mid 86.845394 -254.359051)
		(end 86.658196 -254.409194)
		(width 0.088646)
		(layer "In6.Cu")
		(net "M_C_CPU1_SA_RSP<1>")
	)
	(arc
		(start 86.658196 -254.409194)
		(mid 86.375494 -254.48497)
		(end 86.092792 -254.409194)
		(width 0.088646)
		(layer "In6.Cu")
		(net "M_C_CPU1_SA_RSP<1>")
	)
	(arc
		(start 94.161864 -254.41783)
		(mid 93.885389 -254.48515)
		(end 93.611192 -254.409194)
		(width 0.088646)
		(layer "In6.Cu")
		(net "M_C_CPU1_SA_RSP<1>")
	)
	(arc
		(start 86.02853 -254.366014)
		(mid 85.894004 -254.255176)
		(end 85.76691 -254.13589)
		(width 0.088646)
		(layer "In6.Cu")
		(net "M_C_CPU1_SA_RSP<1>")
	)
	(arc
		(start 89.477596 -254.409194)
		(mid 89.194894 -254.48497)
		(end 88.912192 -254.409194)
		(width 0.088646)
		(layer "In6.Cu")
		(net "M_C_CPU1_SA_RSP<1>")
	)
	(arc
		(start 90.791792 -254.409194)
		(mid 90.604594 -254.359051)
		(end 90.417396 -254.409194)
		(width 0.088646)
		(layer "In6.Cu")
		(net "M_C_CPU1_SA_RSP<1>")
	)
	(arc
		(start 91.731846 -254.409194)
		(mid 91.544648 -254.359051)
		(end 91.35745 -254.409194)
		(width 0.088646)
		(layer "In6.Cu")
		(net "M_C_CPU1_SA_RSP<1>")
	)
	(arc
		(start 90.417396 -254.409194)
		(mid 90.134694 -254.48497)
		(end 89.851992 -254.409194)
		(width 0.088646)
		(layer "In6.Cu")
		(net "M_C_CPU1_SA_RSP<1>")
	)
	(arc
		(start 93.222064 -254.41783)
		(mid 92.945589 -254.48515)
		(end 92.671392 -254.409194)
		(width 0.088646)
		(layer "In6.Cu")
		(net "M_C_CPU1_SA_RSP<1>")
	)
	(arc
		(start 87.597996 -254.409194)
		(mid 87.315294 -254.48497)
		(end 87.032592 -254.409194)
		(width 0.088646)
		(layer "In6.Cu")
		(net "M_C_CPU1_SA_RSP<1>")
	)
	(arc
		(start 94.459298 -253.919736)
		(mid 94.385307 -254.199302)
		(end 94.182692 -254.405638)
		(width 0.088646)
		(layer "In6.Cu")
		(net "M_C_CPU1_SA_RSP<1>")
	)
	(arc
		(start 88.537796 -254.409194)
		(mid 88.255094 -254.48497)
		(end 87.972392 -254.409194)
		(width 0.088646)
		(layer "In6.Cu")
		(net "M_C_CPU1_SA_RSP<1>")
	)
	(arc
		(start 93.611192 -254.409194)
		(mid 93.423994 -254.359051)
		(end 93.236796 -254.409194)
		(width 0.088646)
		(layer "In6.Cu")
		(net "M_C_CPU1_SA_RSP<1>")
	)
	(arc
		(start 88.912192 -254.409194)
		(mid 88.724994 -254.359051)
		(end 88.537796 -254.409194)
		(width 0.088646)
		(layer "In6.Cu")
		(net "M_C_CPU1_SA_RSP<1>")
	)
	(arc
		(start 87.972392 -254.409194)
		(mid 87.785194 -254.359051)
		(end 87.597996 -254.409194)
		(width 0.088646)
		(layer "In6.Cu")
		(net "M_C_CPU1_SA_RSP<1>")
	)
	(arc
		(start 96.143826 -253.862586)
		(mid 96.086775 -253.713963)
		(end 95.973138 -253.60249)
		(width 0.088646)
		(layer "In6.Cu")
		(net "M_C_CPU1_SA_RSP<1>")
	)
	(arc
		(start 92.286582 -254.41529)
		(mid 92.008404 -254.485013)
		(end 91.731846 -254.409194)
		(width 0.088646)
		(layer "In6.Cu")
		(net "M_C_CPU1_SA_RSP<1>")
	)
	(arc
		(start 95.586296 -253.595378)
		(mid 95.312097 -253.671213)
		(end 95.035624 -253.604014)
		(width 0.088646)
		(layer "In6.Cu")
		(net "M_C_CPU1_SA_RSP<1>")
	)
	(arc
		(start 91.347036 -254.41529)
		(mid 91.068604 -254.485136)
		(end 90.791792 -254.409194)
		(width 0.088646)
		(layer "In6.Cu")
		(net "M_C_CPU1_SA_RSP<1>")
	)
	(arc
		(start 95.948754 -253.58852)
		(mid 95.766643 -253.545195)
		(end 95.586296 -253.595378)
		(width 0.088646)
		(layer "In6.Cu")
		(net "M_C_CPU1_SA_RSP<1>")
	)
	(arc
		(start 94.646496 -253.595378)
		(mid 94.511563 -253.728732)
		(end 94.459298 -253.9111)
		(width 0.088646)
		(layer "In6.Cu")
		(net "M_C_CPU1_SA_RSP<1>")
	)
	(arc
		(start 95.020892 -253.595378)
		(mid 94.833694 -253.545235)
		(end 94.646496 -253.595378)
		(width 0.088646)
		(layer "In6.Cu")
		(net "M_C_CPU1_SA_RSP<1>")
	)
	(arc
		(start 89.851992 -254.409194)
		(mid 89.664794 -254.359051)
		(end 89.477596 -254.409194)
		(width 0.088646)
		(layer "In6.Cu")
		(net "M_C_CPU1_SA_RSP<1>")
	)
	(arc
		(start 92.671392 -254.409194)
		(mid 92.484194 -254.359051)
		(end 92.296996 -254.409194)
		(width 0.088646)
		(layer "In6.Cu")
		(net "M_C_CPU1_SA_RSP<1>")
	)
	(arc
		(start 86.092792 -254.409194)
		(mid 86.059922 -254.388704)
		(end 86.02853 -254.366014)
		(width 0.088646)
		(layer "In6.Cu")
		(net "M_C_CPU1_SA_RSP<1>")
	)
	(segment
		(start 95.303848 -254.733298)
		(end 95.303594 -254.733552)
		(width 0.20066)
		(layer "F.Cu")
		(net "M_C_CPU1_SA_RSP<0>")
	)
	(segment
		(start 95.303848 -254.197612)
		(end 95.303848 -254.733298)
		(width 0.20066)
		(layer "F.Cu")
		(net "M_C_CPU1_SA_RSP<0>")
	)
	(segment
		(start 23.228046 -244.066568)
		(end 24.332946 -244.066568)
		(width 0.20066)
		(layer "F.Cu")
		(net "M_C_CPU1_SA_RSP<0>")
	)
	(segment
		(start 80.873092 -254.387604)
		(end 78.699106 -255.288034)
		(width 0.18288)
		(layer "In6.Cu")
		(net "M_C_CPU1_SA_RSP<0>")
	)
	(segment
		(start 29.946092 -247.890792)
		(end 28.846526 -246.791226)
		(width 0.18288)
		(layer "In6.Cu")
		(net "M_C_CPU1_SA_RSP<0>")
	)
	(segment
		(start 94.646496 -255.22301)
		(end 94.64675 -255.223264)
		(width 0.088646)
		(layer "In6.Cu")
		(net "M_C_CPU1_SA_RSP<0>")
	)
	(segment
		(start 42.295572 -251.19965)
		(end 42.112692 -251.01677)
		(width 0.18288)
		(layer "In6.Cu")
		(net "M_C_CPU1_SA_RSP<0>")
	)
	(segment
		(start 47.733966 -251.505466)
		(end 47.520606 -251.292106)
		(width 0.18288)
		(layer "In6.Cu")
		(net "M_C_CPU1_SA_RSP<0>")
	)
	(segment
		(start 38.694868 -250.766072)
		(end 36.669726 -248.74093)
		(width 0.18288)
		(layer "In6.Cu")
		(net "M_C_CPU1_SA_RSP<0>")
	)
	(segment
		(start 66.475102 -255.288288)
		(end 51.837844 -255.288288)
		(width 0.18288)
		(layer "In6.Cu")
		(net "M_C_CPU1_SA_RSP<0>")
	)
	(segment
		(start 88.452706 -255.22936)
		(end 88.442292 -255.223264)
		(width 0.088646)
		(layer "In6.Cu")
		(net "M_C_CPU1_SA_RSP<0>")
	)
	(segment
		(start 47.097696 -251.292106)
		(end 47.096426 -251.290836)
		(width 0.18288)
		(layer "In6.Cu")
		(net "M_C_CPU1_SA_RSP<0>")
	)
	(segment
		(start 92.211906 -255.22936)
		(end 92.201492 -255.223264)
		(width 0.088646)
		(layer "In6.Cu")
		(net "M_C_CPU1_SA_RSP<0>")
	)
	(segment
		(start 84.760054 -254.387604)
		(end 84.434934 -254.387604)
		(width 0.088646)
		(layer "In6.Cu")
		(net "M_C_CPU1_SA_RSP<0>")
	)
	(segment
		(start 25.417526 -245.151148)
		(end 24.332946 -244.066568)
		(width 0.18288)
		(layer "In6.Cu")
		(net "M_C_CPU1_SA_RSP<0>")
	)
	(segment
		(start 46.180756 -251.290836)
		(end 45.329602 -250.439682)
		(width 0.18288)
		(layer "In6.Cu")
		(net "M_C_CPU1_SA_RSP<0>")
	)
	(segment
		(start 66.475356 -255.288034)
		(end 66.475102 -255.288288)
		(width 0.18288)
		(layer "In6.Cu")
		(net "M_C_CPU1_SA_RSP<0>")
	)
	(segment
		(start 42.803572 -251.01677)
		(end 42.620692 -251.19965)
		(width 0.18288)
		(layer "In6.Cu")
		(net "M_C_CPU1_SA_RSP<0>")
	)
	(segment
		(start 84.434934 -254.387604)
		(end 80.873092 -254.387604)
		(width 0.18288)
		(layer "In6.Cu")
		(net "M_C_CPU1_SA_RSP<0>")
	)
	(segment
		(start 32.423862 -247.890792)
		(end 29.946092 -247.890792)
		(width 0.18288)
		(layer "In6.Cu")
		(net "M_C_CPU1_SA_RSP<0>")
	)
	(segment
		(start 26.348182 -246.791226)
		(end 25.417526 -245.86057)
		(width 0.18288)
		(layer "In6.Cu")
		(net "M_C_CPU1_SA_RSP<0>")
	)
	(segment
		(start 47.520606 -251.292106)
		(end 47.097696 -251.292106)
		(width 0.18288)
		(layer "In6.Cu")
		(net "M_C_CPU1_SA_RSP<0>")
	)
	(segment
		(start 28.846526 -246.791226)
		(end 26.348182 -246.791226)
		(width 0.18288)
		(layer "In6.Cu")
		(net "M_C_CPU1_SA_RSP<0>")
	)
	(segment
		(start 25.417526 -245.86057)
		(end 25.417526 -245.151148)
		(width 0.18288)
		(layer "In6.Cu")
		(net "M_C_CPU1_SA_RSP<0>")
	)
	(segment
		(start 48.443896 -252.870716)
		(end 47.733966 -252.160786)
		(width 0.18288)
		(layer "In6.Cu")
		(net "M_C_CPU1_SA_RSP<0>")
	)
	(segment
		(start 90.332306 -255.22936)
		(end 90.321892 -255.223264)
		(width 0.088646)
		(layer "In6.Cu")
		(net "M_C_CPU1_SA_RSP<0>")
	)
	(segment
		(start 40.406828 -250.439682)
		(end 40.080438 -250.766072)
		(width 0.18288)
		(layer "In6.Cu")
		(net "M_C_CPU1_SA_RSP<0>")
	)
	(segment
		(start 33.274 -248.74093)
		(end 32.423862 -247.890792)
		(width 0.18288)
		(layer "In6.Cu")
		(net "M_C_CPU1_SA_RSP<0>")
	)
	(segment
		(start 91.827096 -255.223264)
		(end 91.816682 -255.22936)
		(width 0.088646)
		(layer "In6.Cu")
		(net "M_C_CPU1_SA_RSP<0>")
	)
	(segment
		(start 36.669726 -248.74093)
		(end 33.274 -248.74093)
		(width 0.18288)
		(layer "In6.Cu")
		(net "M_C_CPU1_SA_RSP<0>")
	)
	(segment
		(start 47.096426 -251.290836)
		(end 46.180756 -251.290836)
		(width 0.18288)
		(layer "In6.Cu")
		(net "M_C_CPU1_SA_RSP<0>")
	)
	(segment
		(start 50.056542 -253.506986)
		(end 48.443896 -252.870716)
		(width 0.18288)
		(layer "In6.Cu")
		(net "M_C_CPU1_SA_RSP<0>")
	)
	(segment
		(start 78.699106 -255.288034)
		(end 66.475356 -255.288034)
		(width 0.18288)
		(layer "In6.Cu")
		(net "M_C_CPU1_SA_RSP<0>")
	)
	(segment
		(start 40.080438 -250.766072)
		(end 38.694868 -250.766072)
		(width 0.18288)
		(layer "In6.Cu")
		(net "M_C_CPU1_SA_RSP<0>")
	)
	(segment
		(start 42.986452 -250.439682)
		(end 42.803572 -250.622562)
		(width 0.18288)
		(layer "In6.Cu")
		(net "M_C_CPU1_SA_RSP<0>")
	)
	(segment
		(start 41.929812 -250.439682)
		(end 40.406828 -250.439682)
		(width 0.18288)
		(layer "In6.Cu")
		(net "M_C_CPU1_SA_RSP<0>")
	)
	(segment
		(start 45.329602 -250.439682)
		(end 42.986452 -250.439682)
		(width 0.18288)
		(layer "In6.Cu")
		(net "M_C_CPU1_SA_RSP<0>")
	)
	(segment
		(start 51.837844 -255.288288)
		(end 50.056542 -253.506986)
		(width 0.18288)
		(layer "In6.Cu")
		(net "M_C_CPU1_SA_RSP<0>")
	)
	(segment
		(start 93.156278 -255.2319)
		(end 93.141546 -255.223264)
		(width 0.088646)
		(layer "In6.Cu")
		(net "M_C_CPU1_SA_RSP<0>")
	)
	(segment
		(start 42.112692 -251.01677)
		(end 42.112692 -250.622562)
		(width 0.18288)
		(layer "In6.Cu")
		(net "M_C_CPU1_SA_RSP<0>")
	)
	(segment
		(start 89.39276 -255.22936)
		(end 89.382346 -255.223264)
		(width 0.088646)
		(layer "In6.Cu")
		(net "M_C_CPU1_SA_RSP<0>")
	)
	(segment
		(start 42.112692 -250.622562)
		(end 41.929812 -250.439682)
		(width 0.18288)
		(layer "In6.Cu")
		(net "M_C_CPU1_SA_RSP<0>")
	)
	(segment
		(start 95.303594 -254.733552)
		(end 94.67596 -255.206246)
		(width 0.088646)
		(layer "In6.Cu")
		(net "M_C_CPU1_SA_RSP<0>")
	)
	(segment
		(start 47.733966 -252.160786)
		(end 47.733966 -251.505466)
		(width 0.18288)
		(layer "In6.Cu")
		(net "M_C_CPU1_SA_RSP<0>")
	)
	(segment
		(start 85.505798 -255.133348)
		(end 84.760054 -254.387604)
		(width 0.088646)
		(layer "In6.Cu")
		(net "M_C_CPU1_SA_RSP<0>")
	)
	(segment
		(start 42.620692 -251.19965)
		(end 42.295572 -251.19965)
		(width 0.18288)
		(layer "In6.Cu")
		(net "M_C_CPU1_SA_RSP<0>")
	)
	(segment
		(start 94.096078 -255.2319)
		(end 94.081346 -255.223264)
		(width 0.088646)
		(layer "In6.Cu")
		(net "M_C_CPU1_SA_RSP<0>")
	)
	(segment
		(start 42.803572 -250.622562)
		(end 42.803572 -251.01677)
		(width 0.18288)
		(layer "In6.Cu")
		(net "M_C_CPU1_SA_RSP<0>")
	)
	(segment
		(start 94.67596 -255.206246)
		(end 94.646496 -255.22301)
		(width 0.088646)
		(layer "In6.Cu")
		(net "M_C_CPU1_SA_RSP<0>")
	)
	(arc
		(start 92.76715 -255.223264)
		(mid 92.490337 -255.2991)
		(end 92.211906 -255.22936)
		(width 0.088646)
		(layer "In6.Cu")
		(net "M_C_CPU1_SA_RSP<0>")
	)
	(arc
		(start 87.128096 -255.223264)
		(mid 86.845394 -255.299006)
		(end 86.562692 -255.223264)
		(width 0.088646)
		(layer "In6.Cu")
		(net "M_C_CPU1_SA_RSP<0>")
	)
	(arc
		(start 92.201492 -255.223264)
		(mid 92.014294 -255.173121)
		(end 91.827096 -255.223264)
		(width 0.088646)
		(layer "In6.Cu")
		(net "M_C_CPU1_SA_RSP<0>")
	)
	(arc
		(start 87.502492 -255.223264)
		(mid 87.315294 -255.173121)
		(end 87.128096 -255.223264)
		(width 0.088646)
		(layer "In6.Cu")
		(net "M_C_CPU1_SA_RSP<0>")
	)
	(arc
		(start 93.141546 -255.223264)
		(mid 92.954348 -255.173121)
		(end 92.76715 -255.223264)
		(width 0.088646)
		(layer "In6.Cu")
		(net "M_C_CPU1_SA_RSP<0>")
	)
	(arc
		(start 88.442292 -255.223264)
		(mid 88.255094 -255.173121)
		(end 88.067896 -255.223264)
		(width 0.088646)
		(layer "In6.Cu")
		(net "M_C_CPU1_SA_RSP<0>")
	)
	(arc
		(start 90.88755 -255.223264)
		(mid 90.610737 -255.2991)
		(end 90.332306 -255.22936)
		(width 0.088646)
		(layer "In6.Cu")
		(net "M_C_CPU1_SA_RSP<0>")
	)
	(arc
		(start 93.70695 -255.223264)
		(mid 93.432721 -255.299189)
		(end 93.156278 -255.2319)
		(width 0.088646)
		(layer "In6.Cu")
		(net "M_C_CPU1_SA_RSP<0>")
	)
	(arc
		(start 91.261946 -255.223264)
		(mid 91.074748 -255.173121)
		(end 90.88755 -255.223264)
		(width 0.088646)
		(layer "In6.Cu")
		(net "M_C_CPU1_SA_RSP<0>")
	)
	(arc
		(start 94.64675 -255.223264)
		(mid 94.372521 -255.299189)
		(end 94.096078 -255.2319)
		(width 0.088646)
		(layer "In6.Cu")
		(net "M_C_CPU1_SA_RSP<0>")
	)
	(arc
		(start 89.382346 -255.223264)
		(mid 89.195148 -255.173121)
		(end 89.00795 -255.223264)
		(width 0.088646)
		(layer "In6.Cu")
		(net "M_C_CPU1_SA_RSP<0>")
	)
	(arc
		(start 88.067896 -255.223264)
		(mid 87.785194 -255.299006)
		(end 87.502492 -255.223264)
		(width 0.088646)
		(layer "In6.Cu")
		(net "M_C_CPU1_SA_RSP<0>")
	)
	(arc
		(start 89.00795 -255.223264)
		(mid 88.731137 -255.2991)
		(end 88.452706 -255.22936)
		(width 0.088646)
		(layer "In6.Cu")
		(net "M_C_CPU1_SA_RSP<0>")
	)
	(arc
		(start 89.947496 -255.223264)
		(mid 89.670937 -255.298973)
		(end 89.39276 -255.22936)
		(width 0.088646)
		(layer "In6.Cu")
		(net "M_C_CPU1_SA_RSP<0>")
	)
	(arc
		(start 90.321892 -255.223264)
		(mid 90.134694 -255.173121)
		(end 89.947496 -255.223264)
		(width 0.088646)
		(layer "In6.Cu")
		(net "M_C_CPU1_SA_RSP<0>")
	)
	(arc
		(start 94.081346 -255.223264)
		(mid 93.894148 -255.173121)
		(end 93.70695 -255.223264)
		(width 0.088646)
		(layer "In6.Cu")
		(net "M_C_CPU1_SA_RSP<0>")
	)
	(arc
		(start 86.188296 -255.223264)
		(mid 85.831773 -255.294167)
		(end 85.505798 -255.133348)
		(width 0.088646)
		(layer "In6.Cu")
		(net "M_C_CPU1_SA_RSP<0>")
	)
	(arc
		(start 91.816682 -255.22936)
		(mid 91.538504 -255.299052)
		(end 91.261946 -255.223264)
		(width 0.088646)
		(layer "In6.Cu")
		(net "M_C_CPU1_SA_RSP<0>")
	)
	(arc
		(start 86.562692 -255.223264)
		(mid 86.375494 -255.173121)
		(end 86.188296 -255.223264)
		(width 0.088646)
		(layer "In6.Cu")
		(net "M_C_CPU1_SA_RSP<0>")
	)
	(segment
		(start 25.572974 -258.95554)
		(end 26.20391 -258.95554)
		(width 0.20066)
		(layer "F.Cu")
		(net "M_C_CPU1_SA_PAR")
	)
	(segment
		(start 31.876746 -259.366766)
		(end 30.771846 -259.366766)
		(width 0.20066)
		(layer "F.Cu")
		(net "M_C_CPU1_SA_PAR")
	)
	(segment
		(start 28.529026 -258.941824)
		(end 28.640532 -258.941824)
		(width 0.20066)
		(layer "F.Cu")
		(net "M_C_CPU1_SA_PAR")
	)
	(segment
		(start 26.212546 -258.95554)
		(end 26.226262 -258.941824)
		(width 0.101854)
		(layer "F.Cu")
		(net "M_C_CPU1_SA_PAR")
	)
	(segment
		(start 28.198318 -258.941824)
		(end 28.529026 -258.941824)
		(width 0.101854)
		(layer "F.Cu")
		(net "M_C_CPU1_SA_PAR")
	)
	(segment
		(start 25.211278 -259.60578)
		(end 25.432512 -259.384546)
		(width 0.20066)
		(layer "F.Cu")
		(net "M_C_CPU1_SA_PAR")
	)
	(segment
		(start 25.57272 -258.955286)
		(end 25.572974 -258.95554)
		(width 0.20066)
		(layer "F.Cu")
		(net "M_C_CPU1_SA_PAR")
	)
	(segment
		(start 25.432512 -259.095494)
		(end 25.57272 -258.955286)
		(width 0.20066)
		(layer "F.Cu")
		(net "M_C_CPU1_SA_PAR")
	)
	(segment
		(start 28.640532 -258.941824)
		(end 29.065474 -259.366766)
		(width 0.20066)
		(layer "F.Cu")
		(net "M_C_CPU1_SA_PAR")
	)
	(segment
		(start 92.014294 -253.383796)
		(end 92.014548 -253.38405)
		(width 0.20066)
		(layer "F.Cu")
		(net "M_C_CPU1_SA_PAR")
	)
	(segment
		(start 23.228046 -259.366766)
		(end 24.562308 -259.366766)
		(width 0.20066)
		(layer "F.Cu")
		(net "M_C_CPU1_SA_PAR")
	)
	(segment
		(start 24.801322 -259.60578)
		(end 25.211278 -259.60578)
		(width 0.20066)
		(layer "F.Cu")
		(net "M_C_CPU1_SA_PAR")
	)
	(segment
		(start 24.562308 -259.366766)
		(end 24.801322 -259.60578)
		(width 0.20066)
		(layer "F.Cu")
		(net "M_C_CPU1_SA_PAR")
	)
	(segment
		(start 26.226262 -258.941824)
		(end 28.198318 -258.941824)
		(width 0.1016)
		(layer "F.Cu")
		(net "M_C_CPU1_SA_PAR")
	)
	(segment
		(start 29.065474 -259.366766)
		(end 30.771846 -259.366766)
		(width 0.20066)
		(layer "F.Cu")
		(net "M_C_CPU1_SA_PAR")
	)
	(segment
		(start 25.432512 -259.384546)
		(end 25.432512 -259.095494)
		(width 0.20066)
		(layer "F.Cu")
		(net "M_C_CPU1_SA_PAR")
	)
	(segment
		(start 26.20391 -258.95554)
		(end 26.212546 -258.95554)
		(width 0.101854)
		(layer "F.Cu")
		(net "M_C_CPU1_SA_PAR")
	)
	(segment
		(start 92.014548 -253.38405)
		(end 92.014548 -253.919736)
		(width 0.20066)
		(layer "F.Cu")
		(net "M_C_CPU1_SA_PAR")
	)
	(segment
		(start 71.703438 -255.50114)
		(end 67.099434 -257.408172)
		(width 0.18288)
		(layer "In4.Cu")
		(net "M_C_CPU1_SA_PAR")
	)
	(segment
		(start 56.33085 -257.408426)
		(end 53.403754 -257.990594)
		(width 0.18288)
		(layer "In4.Cu")
		(net "M_C_CPU1_SA_PAR")
	)
	(segment
		(start 84.434934 -253.02337)
		(end 82.495136 -253.02337)
		(width 0.18288)
		(layer "In4.Cu")
		(net "M_C_CPU1_SA_PAR")
	)
	(segment
		(start 86.110318 -254.184912)
		(end 84.948776 -253.02337)
		(width 0.088646)
		(layer "In4.Cu")
		(net "M_C_CPU1_SA_PAR")
	)
	(segment
		(start 35.37458 -260.643624)
		(end 34.097722 -259.366766)
		(width 0.18288)
		(layer "In4.Cu")
		(net "M_C_CPU1_SA_PAR")
	)
	(segment
		(start 84.948776 -253.02337)
		(end 84.434934 -253.02337)
		(width 0.088646)
		(layer "In4.Cu")
		(net "M_C_CPU1_SA_PAR")
	)
	(segment
		(start 92.014548 -253.919736)
		(end 91.895168 -253.919736)
		(width 0.088646)
		(layer "In4.Cu")
		(net "M_C_CPU1_SA_PAR")
	)
	(segment
		(start 37.544502 -260.643624)
		(end 35.37458 -260.643624)
		(width 0.18288)
		(layer "In4.Cu")
		(net "M_C_CPU1_SA_PAR")
	)
	(segment
		(start 65.925954 -257.408426)
		(end 56.33085 -257.408426)
		(width 0.18288)
		(layer "In4.Cu")
		(net "M_C_CPU1_SA_PAR")
	)
	(segment
		(start 80.017366 -255.50114)
		(end 71.703438 -255.50114)
		(width 0.18288)
		(layer "In4.Cu")
		(net "M_C_CPU1_SA_PAR")
	)
	(segment
		(start 50.14214 -257.990594)
		(end 49.191164 -258.94157)
		(width 0.18288)
		(layer "In4.Cu")
		(net "M_C_CPU1_SA_PAR")
	)
	(segment
		(start 90.904822 -254.254254)
		(end 90.88755 -254.244094)
		(width 0.088646)
		(layer "In4.Cu")
		(net "M_C_CPU1_SA_PAR")
	)
	(segment
		(start 39.246556 -258.94157)
		(end 37.544502 -260.643624)
		(width 0.18288)
		(layer "In4.Cu")
		(net "M_C_CPU1_SA_PAR")
	)
	(segment
		(start 53.403754 -257.990594)
		(end 50.14214 -257.990594)
		(width 0.18288)
		(layer "In4.Cu")
		(net "M_C_CPU1_SA_PAR")
	)
	(segment
		(start 82.495136 -253.02337)
		(end 80.017366 -255.50114)
		(width 0.18288)
		(layer "In4.Cu")
		(net "M_C_CPU1_SA_PAR")
	)
	(segment
		(start 49.191164 -258.94157)
		(end 39.246556 -258.94157)
		(width 0.18288)
		(layer "In4.Cu")
		(net "M_C_CPU1_SA_PAR")
	)
	(segment
		(start 34.097722 -259.366766)
		(end 31.876746 -259.366766)
		(width 0.18288)
		(layer "In4.Cu")
		(net "M_C_CPU1_SA_PAR")
	)
	(segment
		(start 90.332306 -254.237998)
		(end 90.321892 -254.244094)
		(width 0.088646)
		(layer "In4.Cu")
		(net "M_C_CPU1_SA_PAR")
	)
	(segment
		(start 65.926208 -257.408172)
		(end 65.925954 -257.408426)
		(width 0.18288)
		(layer "In4.Cu")
		(net "M_C_CPU1_SA_PAR")
	)
	(segment
		(start 67.099434 -257.408172)
		(end 65.926208 -257.408172)
		(width 0.18288)
		(layer "In4.Cu")
		(net "M_C_CPU1_SA_PAR")
	)
	(arc
		(start 91.2622 -254.244348)
		(mid 91.08478 -254.29457)
		(end 90.904822 -254.254254)
		(width 0.088646)
		(layer "In4.Cu")
		(net "M_C_CPU1_SA_PAR")
	)
	(arc
		(start 90.88755 -254.244094)
		(mid 90.610737 -254.168224)
		(end 90.332306 -254.237998)
		(width 0.088646)
		(layer "In4.Cu")
		(net "M_C_CPU1_SA_PAR")
	)
	(arc
		(start 90.321892 -254.244094)
		(mid 90.134694 -254.294237)
		(end 89.947496 -254.244094)
		(width 0.088646)
		(layer "In4.Cu")
		(net "M_C_CPU1_SA_PAR")
	)
	(arc
		(start 87.128096 -254.244094)
		(mid 86.845394 -254.168318)
		(end 86.562692 -254.244094)
		(width 0.088646)
		(layer "In4.Cu")
		(net "M_C_CPU1_SA_PAR")
	)
	(arc
		(start 88.067896 -254.244094)
		(mid 87.785194 -254.168318)
		(end 87.502492 -254.244094)
		(width 0.088646)
		(layer "In4.Cu")
		(net "M_C_CPU1_SA_PAR")
	)
	(arc
		(start 89.007696 -254.244094)
		(mid 88.724994 -254.168318)
		(end 88.442292 -254.244094)
		(width 0.088646)
		(layer "In4.Cu")
		(net "M_C_CPU1_SA_PAR")
	)
	(arc
		(start 88.442292 -254.244094)
		(mid 88.255094 -254.294237)
		(end 88.067896 -254.244094)
		(width 0.088646)
		(layer "In4.Cu")
		(net "M_C_CPU1_SA_PAR")
	)
	(arc
		(start 89.382092 -254.244094)
		(mid 89.194894 -254.294237)
		(end 89.007696 -254.244094)
		(width 0.088646)
		(layer "In4.Cu")
		(net "M_C_CPU1_SA_PAR")
	)
	(arc
		(start 86.188296 -254.244094)
		(mid 86.147366 -254.217061)
		(end 86.110318 -254.184912)
		(width 0.088646)
		(layer "In4.Cu")
		(net "M_C_CPU1_SA_PAR")
	)
	(arc
		(start 87.502492 -254.244094)
		(mid 87.315294 -254.294237)
		(end 87.128096 -254.244094)
		(width 0.088646)
		(layer "In4.Cu")
		(net "M_C_CPU1_SA_PAR")
	)
	(arc
		(start 89.947496 -254.244094)
		(mid 89.664794 -254.168318)
		(end 89.382092 -254.244094)
		(width 0.088646)
		(layer "In4.Cu")
		(net "M_C_CPU1_SA_PAR")
	)
	(arc
		(start 86.562692 -254.244094)
		(mid 86.375494 -254.294237)
		(end 86.188296 -254.244094)
		(width 0.088646)
		(layer "In4.Cu")
		(net "M_C_CPU1_SA_PAR")
	)
	(arc
		(start 91.653614 -254.019812)
		(mid 91.519738 -254.125464)
		(end 91.365324 -254.197866)
		(width 0.088646)
		(layer "In4.Cu")
		(net "M_C_CPU1_SA_PAR")
	)
	(arc
		(start 91.365324 -254.197866)
		(mid 91.312592 -254.218512)
		(end 91.2622 -254.244348)
		(width 0.088646)
		(layer "In4.Cu")
		(net "M_C_CPU1_SA_PAR")
	)
	(arc
		(start 91.895168 -253.919736)
		(mid 91.764432 -253.945741)
		(end 91.653614 -254.019812)
		(width 0.088646)
		(layer "In4.Cu")
		(net "M_C_CPU1_SA_PAR")
	)
	(segment
		(start 96.713294 -260.430518)
		(end 96.71304 -260.430772)
		(width 0.20066)
		(layer "F.Cu")
		(net "M_C_CPU1_SA_DQS_DP<9>")
	)
	(segment
		(start 32.375348 -273.652996)
		(end 32.8803 -273.652996)
		(width 0.20066)
		(layer "F.Cu")
		(net "M_C_CPU1_SA_DQS_DP<9>")
	)
	(segment
		(start 29.89453 -273.39163)
		(end 31.972504 -273.39163)
		(width 0.1016)
		(layer "F.Cu")
		(net "M_C_CPU1_SA_DQS_DP<9>")
	)
	(segment
		(start 35.976814 -273.816572)
		(end 34.871914 -273.816572)
		(width 0.20066)
		(layer "F.Cu")
		(net "M_C_CPU1_SA_DQS_DP<9>")
	)
	(segment
		(start 32.025082 -273.39163)
		(end 32.113982 -273.39163)
		(width 0.20066)
		(layer "F.Cu")
		(net "M_C_CPU1_SA_DQS_DP<9>")
	)
	(segment
		(start 28.398216 -274.077938)
		(end 28.820618 -273.655536)
		(width 0.20066)
		(layer "F.Cu")
		(net "M_C_CPU1_SA_DQS_DP<9>")
	)
	(segment
		(start 28.820618 -273.655536)
		(end 29.18079 -273.655536)
		(width 0.20066)
		(layer "F.Cu")
		(net "M_C_CPU1_SA_DQS_DP<9>")
	)
	(segment
		(start 29.444696 -273.39163)
		(end 29.516324 -273.39163)
		(width 0.20066)
		(layer "F.Cu")
		(net "M_C_CPU1_SA_DQS_DP<9>")
	)
	(segment
		(start 34.120836 -274.077938)
		(end 34.382202 -273.816572)
		(width 0.20066)
		(layer "F.Cu")
		(net "M_C_CPU1_SA_DQS_DP<9>")
	)
	(segment
		(start 29.18079 -273.655536)
		(end 29.444696 -273.39163)
		(width 0.20066)
		(layer "F.Cu")
		(net "M_C_CPU1_SA_DQS_DP<9>")
	)
	(segment
		(start 33.516316 -274.077938)
		(end 34.120836 -274.077938)
		(width 0.20066)
		(layer "F.Cu")
		(net "M_C_CPU1_SA_DQS_DP<9>")
	)
	(segment
		(start 96.713294 -259.894832)
		(end 96.713294 -260.430518)
		(width 0.20066)
		(layer "F.Cu")
		(net "M_C_CPU1_SA_DQS_DP<9>")
	)
	(segment
		(start 31.972504 -273.39163)
		(end 32.025082 -273.39163)
		(width 0.101854)
		(layer "F.Cu")
		(net "M_C_CPU1_SA_DQS_DP<9>")
	)
	(segment
		(start 29.516324 -273.39163)
		(end 29.89453 -273.39163)
		(width 0.101854)
		(layer "F.Cu")
		(net "M_C_CPU1_SA_DQS_DP<9>")
	)
	(segment
		(start 27.802586 -273.816572)
		(end 28.063952 -274.077938)
		(width 0.20066)
		(layer "F.Cu")
		(net "M_C_CPU1_SA_DQS_DP<9>")
	)
	(segment
		(start 32.113982 -273.39163)
		(end 32.375348 -273.652996)
		(width 0.20066)
		(layer "F.Cu")
		(net "M_C_CPU1_SA_DQS_DP<9>")
	)
	(segment
		(start 28.063952 -274.077938)
		(end 28.398216 -274.077938)
		(width 0.20066)
		(layer "F.Cu")
		(net "M_C_CPU1_SA_DQS_DP<9>")
	)
	(segment
		(start 27.328114 -273.816572)
		(end 27.802586 -273.816572)
		(width 0.20066)
		(layer "F.Cu")
		(net "M_C_CPU1_SA_DQS_DP<9>")
	)
	(segment
		(start 34.382202 -273.816572)
		(end 34.871914 -273.816572)
		(width 0.20066)
		(layer "F.Cu")
		(net "M_C_CPU1_SA_DQS_DP<9>")
	)
	(segment
		(start 32.8803 -273.652996)
		(end 33.516316 -274.077938)
		(width 0.20066)
		(layer "F.Cu")
		(net "M_C_CPU1_SA_DQS_DP<9>")
	)
	(segment
		(start 68.372736 -264.169652)
		(end 67.865498 -264.37971)
		(width 0.18288)
		(layer "In6.Cu")
		(net "M_C_CPU1_SA_DQS_DP<9>")
	)
	(segment
		(start 65.161668 -265.634724)
		(end 64.147446 -266.648946)
		(width 0.18288)
		(layer "In6.Cu")
		(net "M_C_CPU1_SA_DQS_DP<9>")
	)
	(segment
		(start 61.851286 -266.226544)
		(end 61.276738 -266.464288)
		(width 0.18288)
		(layer "In6.Cu")
		(net "M_C_CPU1_SA_DQS_DP<9>")
	)
	(segment
		(start 51.198526 -267.442442)
		(end 50.985166 -267.442442)
		(width 0.18288)
		(layer "In6.Cu")
		(net "M_C_CPU1_SA_DQS_DP<9>")
	)
	(segment
		(start 83.018376 -261.647432)
		(end 82.741008 -261.647432)
		(width 0.088646)
		(layer "In6.Cu")
		(net "M_C_CPU1_SA_DQS_DP<9>")
	)
	(segment
		(start 83.80476 -260.860794)
		(end 83.018376 -261.647432)
		(width 0.088646)
		(layer "In6.Cu")
		(net "M_C_CPU1_SA_DQS_DP<9>")
	)
	(segment
		(start 89.397078 -260.746494)
		(end 89.382346 -260.75513)
		(width 0.088646)
		(layer "In6.Cu")
		(net "M_C_CPU1_SA_DQS_DP<9>")
	)
	(segment
		(start 36.23945 -274.079208)
		(end 35.976814 -273.816572)
		(width 0.18288)
		(layer "In6.Cu")
		(net "M_C_CPU1_SA_DQS_DP<9>")
	)
	(segment
		(start 43.759882 -270.0782)
		(end 43.474894 -270.362934)
		(width 0.18288)
		(layer "In6.Cu")
		(net "M_C_CPU1_SA_DQS_DP<9>")
	)
	(segment
		(start 66.55435 -265.05789)
		(end 65.161668 -265.634724)
		(width 0.18288)
		(layer "In6.Cu")
		(net "M_C_CPU1_SA_DQS_DP<9>")
	)
	(segment
		(start 92.211906 -260.749034)
		(end 92.201492 -260.75513)
		(width 0.088646)
		(layer "In6.Cu")
		(net "M_C_CPU1_SA_DQS_DP<9>")
	)
	(segment
		(start 41.690544 -271.790668)
		(end 38.5699 -273.083274)
		(width 0.18288)
		(layer "In6.Cu")
		(net "M_C_CPU1_SA_DQS_DP<9>")
	)
	(segment
		(start 50.581052 -267.697204)
		(end 49.7967 -267.697204)
		(width 0.18288)
		(layer "In6.Cu")
		(net "M_C_CPU1_SA_DQS_DP<9>")
	)
	(segment
		(start 48.02886 -269.171928)
		(end 48.02886 -270.02232)
		(width 0.18288)
		(layer "In6.Cu")
		(net "M_C_CPU1_SA_DQS_DP<9>")
	)
	(segment
		(start 46.480984 -270.247364)
		(end 45.961808 -270.247364)
		(width 0.18288)
		(layer "In6.Cu")
		(net "M_C_CPU1_SA_DQS_DP<9>")
	)
	(segment
		(start 43.474894 -270.362934)
		(end 42.86631 -270.615156)
		(width 0.18288)
		(layer "In6.Cu")
		(net "M_C_CPU1_SA_DQS_DP<9>")
	)
	(segment
		(start 71.790052 -262.888984)
		(end 69.779134 -263.72185)
		(width 0.18288)
		(layer "In6.Cu")
		(net "M_C_CPU1_SA_DQS_DP<9>")
	)
	(segment
		(start 48.684688 -268.5161)
		(end 48.02886 -269.171928)
		(width 0.18288)
		(layer "In6.Cu")
		(net "M_C_CPU1_SA_DQS_DP<9>")
	)
	(segment
		(start 90.336878 -260.746494)
		(end 90.322146 -260.75513)
		(width 0.088646)
		(layer "In6.Cu")
		(net "M_C_CPU1_SA_DQS_DP<9>")
	)
	(segment
		(start 64.147446 -266.648946)
		(end 63.439548 -266.648946)
		(width 0.18288)
		(layer "In6.Cu")
		(net "M_C_CPU1_SA_DQS_DP<9>")
	)
	(segment
		(start 82.681318 -261.587742)
		(end 82.65795 -261.587742)
		(width 0.088646)
		(layer "In6.Cu")
		(net "M_C_CPU1_SA_DQS_DP<9>")
	)
	(segment
		(start 58.533284 -266.964668)
		(end 56.36006 -266.964668)
		(width 0.18288)
		(layer "In6.Cu")
		(net "M_C_CPU1_SA_DQS_DP<9>")
	)
	(segment
		(start 69.779134 -263.72185)
		(end 69.616574 -263.654286)
		(width 0.18288)
		(layer "In6.Cu")
		(net "M_C_CPU1_SA_DQS_DP<9>")
	)
	(segment
		(start 96.71304 -260.430772)
		(end 97.026222 -260.430772)
		(width 0.088646)
		(layer "In6.Cu")
		(net "M_C_CPU1_SA_DQS_DP<9>")
	)
	(segment
		(start 67.291458 -264.752328)
		(end 67.128898 -264.685018)
		(width 0.18288)
		(layer "In6.Cu")
		(net "M_C_CPU1_SA_DQS_DP<9>")
	)
	(segment
		(start 49.184814 -268.30909)
		(end 48.684688 -268.5161)
		(width 0.18288)
		(layer "In6.Cu")
		(net "M_C_CPU1_SA_DQS_DP<9>")
	)
	(segment
		(start 46.735492 -269.992856)
		(end 46.480984 -270.247364)
		(width 0.18288)
		(layer "In6.Cu")
		(net "M_C_CPU1_SA_DQS_DP<9>")
	)
	(segment
		(start 68.535296 -264.236962)
		(end 68.372736 -264.169652)
		(width 0.18288)
		(layer "In6.Cu")
		(net "M_C_CPU1_SA_DQS_DP<9>")
	)
	(segment
		(start 63.439548 -266.648946)
		(end 62.419738 -266.226544)
		(width 0.18288)
		(layer "In6.Cu")
		(net "M_C_CPU1_SA_DQS_DP<9>")
	)
	(segment
		(start 66.62166 -264.895076)
		(end 66.55435 -265.05789)
		(width 0.18288)
		(layer "In6.Cu")
		(net "M_C_CPU1_SA_DQS_DP<9>")
	)
	(segment
		(start 37.022278 -274.277074)
		(end 36.824412 -274.079208)
		(width 0.18288)
		(layer "In6.Cu")
		(net "M_C_CPU1_SA_DQS_DP<9>")
	)
	(segment
		(start 67.798188 -264.542524)
		(end 67.291458 -264.752328)
		(width 0.18288)
		(layer "In6.Cu")
		(net "M_C_CPU1_SA_DQS_DP<9>")
	)
	(segment
		(start 46.885606 -269.992602)
		(end 46.885352 -269.992856)
		(width 0.18288)
		(layer "In6.Cu")
		(net "M_C_CPU1_SA_DQS_DP<9>")
	)
	(segment
		(start 88.452706 -260.749034)
		(end 88.442292 -260.75513)
		(width 0.088646)
		(layer "In6.Cu")
		(net "M_C_CPU1_SA_DQS_DP<9>")
	)
	(segment
		(start 48.02886 -270.02232)
		(end 47.805848 -270.245332)
		(width 0.18288)
		(layer "In6.Cu")
		(net "M_C_CPU1_SA_DQS_DP<9>")
	)
	(segment
		(start 69.616574 -263.654286)
		(end 69.109336 -263.864344)
		(width 0.18288)
		(layer "In6.Cu")
		(net "M_C_CPU1_SA_DQS_DP<9>")
	)
	(segment
		(start 56.36006 -266.964668)
		(end 54.576218 -267.703046)
		(width 0.18288)
		(layer "In6.Cu")
		(net "M_C_CPU1_SA_DQS_DP<9>")
	)
	(segment
		(start 44.178982 -269.6591)
		(end 43.759882 -270.0782)
		(width 0.18288)
		(layer "In6.Cu")
		(net "M_C_CPU1_SA_DQS_DP<9>")
	)
	(segment
		(start 97.026222 -260.430772)
		(end 97.083372 -260.487922)
		(width 0.088646)
		(layer "In6.Cu")
		(net "M_C_CPU1_SA_DQS_DP<9>")
	)
	(segment
		(start 67.128898 -264.685018)
		(end 66.62166 -264.895076)
		(width 0.18288)
		(layer "In6.Cu")
		(net "M_C_CPU1_SA_DQS_DP<9>")
	)
	(segment
		(start 46.885352 -269.992856)
		(end 46.735492 -269.992856)
		(width 0.18288)
		(layer "In6.Cu")
		(net "M_C_CPU1_SA_DQS_DP<9>")
	)
	(segment
		(start 60.279534 -267.461746)
		(end 59.733434 -267.461746)
		(width 0.18288)
		(layer "In6.Cu")
		(net "M_C_CPU1_SA_DQS_DP<9>")
	)
	(segment
		(start 45.373544 -269.6591)
		(end 44.178982 -269.6591)
		(width 0.18288)
		(layer "In6.Cu")
		(net "M_C_CPU1_SA_DQS_DP<9>")
	)
	(segment
		(start 49.7967 -267.697204)
		(end 49.184814 -268.30909)
		(width 0.18288)
		(layer "In6.Cu")
		(net "M_C_CPU1_SA_DQS_DP<9>")
	)
	(segment
		(start 36.824412 -274.079208)
		(end 36.23945 -274.079208)
		(width 0.18288)
		(layer "In6.Cu")
		(net "M_C_CPU1_SA_DQS_DP<9>")
	)
	(segment
		(start 61.276738 -266.464288)
		(end 60.279534 -267.461746)
		(width 0.18288)
		(layer "In6.Cu")
		(net "M_C_CPU1_SA_DQS_DP<9>")
	)
	(segment
		(start 50.83556 -267.442696)
		(end 50.581052 -267.697204)
		(width 0.18288)
		(layer "In6.Cu")
		(net "M_C_CPU1_SA_DQS_DP<9>")
	)
	(segment
		(start 38.5699 -273.083274)
		(end 37.376354 -274.277074)
		(width 0.18288)
		(layer "In6.Cu")
		(net "M_C_CPU1_SA_DQS_DP<9>")
	)
	(segment
		(start 50.985166 -267.442442)
		(end 50.984912 -267.442696)
		(width 0.18288)
		(layer "In6.Cu")
		(net "M_C_CPU1_SA_DQS_DP<9>")
	)
	(segment
		(start 51.346608 -267.442696)
		(end 51.198526 -267.442442)
		(width 0.18288)
		(layer "In6.Cu")
		(net "M_C_CPU1_SA_DQS_DP<9>")
	)
	(segment
		(start 62.419738 -266.226544)
		(end 61.851286 -266.226544)
		(width 0.18288)
		(layer "In6.Cu")
		(net "M_C_CPU1_SA_DQS_DP<9>")
	)
	(segment
		(start 51.606958 -267.703046)
		(end 51.346608 -267.442696)
		(width 0.18288)
		(layer "In6.Cu")
		(net "M_C_CPU1_SA_DQS_DP<9>")
	)
	(segment
		(start 81.415128 -261.587742)
		(end 78.274418 -262.888984)
		(width 0.18288)
		(layer "In6.Cu")
		(net "M_C_CPU1_SA_DQS_DP<9>")
	)
	(segment
		(start 67.865498 -264.37971)
		(end 67.798188 -264.542524)
		(width 0.18288)
		(layer "In6.Cu")
		(net "M_C_CPU1_SA_DQS_DP<9>")
	)
	(segment
		(start 42.86631 -270.615156)
		(end 41.690544 -271.790668)
		(width 0.18288)
		(layer "In6.Cu")
		(net "M_C_CPU1_SA_DQS_DP<9>")
	)
	(segment
		(start 91.27236 -260.749034)
		(end 91.261946 -260.75513)
		(width 0.088646)
		(layer "In6.Cu")
		(net "M_C_CPU1_SA_DQS_DP<9>")
	)
	(segment
		(start 47.499016 -270.245332)
		(end 47.24654 -269.992856)
		(width 0.18288)
		(layer "In6.Cu")
		(net "M_C_CPU1_SA_DQS_DP<9>")
	)
	(segment
		(start 47.093886 -269.992602)
		(end 46.885606 -269.992602)
		(width 0.18288)
		(layer "In6.Cu")
		(net "M_C_CPU1_SA_DQS_DP<9>")
	)
	(segment
		(start 54.576218 -267.703046)
		(end 51.606958 -267.703046)
		(width 0.18288)
		(layer "In6.Cu")
		(net "M_C_CPU1_SA_DQS_DP<9>")
	)
	(segment
		(start 82.65795 -261.587742)
		(end 81.415128 -261.587742)
		(width 0.18288)
		(layer "In6.Cu")
		(net "M_C_CPU1_SA_DQS_DP<9>")
	)
	(segment
		(start 50.984912 -267.442696)
		(end 50.83556 -267.442696)
		(width 0.18288)
		(layer "In6.Cu")
		(net "M_C_CPU1_SA_DQS_DP<9>")
	)
	(segment
		(start 47.805848 -270.245332)
		(end 47.499016 -270.245332)
		(width 0.18288)
		(layer "In6.Cu")
		(net "M_C_CPU1_SA_DQS_DP<9>")
	)
	(segment
		(start 45.961808 -270.247364)
		(end 45.373544 -269.6591)
		(width 0.18288)
		(layer "In6.Cu")
		(net "M_C_CPU1_SA_DQS_DP<9>")
	)
	(segment
		(start 78.274418 -262.888984)
		(end 71.790052 -262.888984)
		(width 0.18288)
		(layer "In6.Cu")
		(net "M_C_CPU1_SA_DQS_DP<9>")
	)
	(segment
		(start 96.915224 -260.746494)
		(end 96.900238 -260.75513)
		(width 0.088646)
		(layer "In6.Cu")
		(net "M_C_CPU1_SA_DQS_DP<9>")
	)
	(segment
		(start 47.24654 -269.992856)
		(end 47.093886 -269.992602)
		(width 0.18288)
		(layer "In6.Cu")
		(net "M_C_CPU1_SA_DQS_DP<9>")
	)
	(segment
		(start 69.109336 -263.864344)
		(end 69.042026 -264.027158)
		(width 0.18288)
		(layer "In6.Cu")
		(net "M_C_CPU1_SA_DQS_DP<9>")
	)
	(segment
		(start 59.733434 -267.461746)
		(end 58.533284 -266.964668)
		(width 0.18288)
		(layer "In6.Cu")
		(net "M_C_CPU1_SA_DQS_DP<9>")
	)
	(segment
		(start 93.156278 -260.746494)
		(end 93.141546 -260.75513)
		(width 0.088646)
		(layer "In6.Cu")
		(net "M_C_CPU1_SA_DQS_DP<9>")
	)
	(segment
		(start 69.042026 -264.027158)
		(end 68.535296 -264.236962)
		(width 0.18288)
		(layer "In6.Cu")
		(net "M_C_CPU1_SA_DQS_DP<9>")
	)
	(segment
		(start 82.741008 -261.647432)
		(end 82.681318 -261.587742)
		(width 0.088646)
		(layer "In6.Cu")
		(net "M_C_CPU1_SA_DQS_DP<9>")
	)
	(segment
		(start 37.376354 -274.277074)
		(end 37.022278 -274.277074)
		(width 0.18288)
		(layer "In6.Cu")
		(net "M_C_CPU1_SA_DQS_DP<9>")
	)
	(arc
		(start 85.622892 -260.75513)
		(mid 85.435694 -260.805273)
		(end 85.248496 -260.75513)
		(width 0.088646)
		(layer "In6.Cu")
		(net "M_C_CPU1_SA_DQS_DP<9>")
	)
	(arc
		(start 93.70695 -260.75513)
		(mid 93.432721 -260.679205)
		(end 93.156278 -260.746494)
		(width 0.088646)
		(layer "In6.Cu")
		(net "M_C_CPU1_SA_DQS_DP<9>")
	)
	(arc
		(start 88.067896 -260.75513)
		(mid 87.785194 -260.679388)
		(end 87.502492 -260.75513)
		(width 0.088646)
		(layer "In6.Cu")
		(net "M_C_CPU1_SA_DQS_DP<9>")
	)
	(arc
		(start 84.378038 -260.787134)
		(mid 84.178247 -260.749647)
		(end 83.975702 -260.766814)
		(width 0.088646)
		(layer "In6.Cu")
		(net "M_C_CPU1_SA_DQS_DP<9>")
	)
	(arc
		(start 96.900238 -260.75513)
		(mid 96.71304 -260.805273)
		(end 96.525842 -260.75513)
		(width 0.088646)
		(layer "In6.Cu")
		(net "M_C_CPU1_SA_DQS_DP<9>")
	)
	(arc
		(start 85.248496 -260.75513)
		(mid 84.965794 -260.679388)
		(end 84.683092 -260.75513)
		(width 0.088646)
		(layer "In6.Cu")
		(net "M_C_CPU1_SA_DQS_DP<9>")
	)
	(arc
		(start 93.141546 -260.75513)
		(mid 92.954348 -260.805273)
		(end 92.76715 -260.75513)
		(width 0.088646)
		(layer "In6.Cu")
		(net "M_C_CPU1_SA_DQS_DP<9>")
	)
	(arc
		(start 87.128096 -260.75513)
		(mid 86.845394 -260.679388)
		(end 86.562692 -260.75513)
		(width 0.088646)
		(layer "In6.Cu")
		(net "M_C_CPU1_SA_DQS_DP<9>")
	)
	(arc
		(start 95.960946 -260.75513)
		(mid 95.773748 -260.805273)
		(end 95.58655 -260.75513)
		(width 0.088646)
		(layer "In6.Cu")
		(net "M_C_CPU1_SA_DQS_DP<9>")
	)
	(arc
		(start 91.827096 -260.75513)
		(mid 91.550537 -260.679421)
		(end 91.27236 -260.749034)
		(width 0.088646)
		(layer "In6.Cu")
		(net "M_C_CPU1_SA_DQS_DP<9>")
	)
	(arc
		(start 89.382346 -260.75513)
		(mid 89.195148 -260.805273)
		(end 89.00795 -260.75513)
		(width 0.088646)
		(layer "In6.Cu")
		(net "M_C_CPU1_SA_DQS_DP<9>")
	)
	(arc
		(start 89.94775 -260.75513)
		(mid 89.673521 -260.679205)
		(end 89.397078 -260.746494)
		(width 0.088646)
		(layer "In6.Cu")
		(net "M_C_CPU1_SA_DQS_DP<9>")
	)
	(arc
		(start 86.562692 -260.75513)
		(mid 86.375494 -260.805273)
		(end 86.188296 -260.75513)
		(width 0.088646)
		(layer "In6.Cu")
		(net "M_C_CPU1_SA_DQS_DP<9>")
	)
	(arc
		(start 95.58655 -260.75513)
		(mid 95.303594 -260.679261)
		(end 95.020638 -260.75513)
		(width 0.088646)
		(layer "In6.Cu")
		(net "M_C_CPU1_SA_DQS_DP<9>")
	)
	(arc
		(start 94.081346 -260.75513)
		(mid 93.894148 -260.805273)
		(end 93.70695 -260.75513)
		(width 0.088646)
		(layer "In6.Cu")
		(net "M_C_CPU1_SA_DQS_DP<9>")
	)
	(arc
		(start 89.00795 -260.75513)
		(mid 88.731137 -260.679294)
		(end 88.452706 -260.749034)
		(width 0.088646)
		(layer "In6.Cu")
		(net "M_C_CPU1_SA_DQS_DP<9>")
	)
	(arc
		(start 83.975702 -260.766814)
		(mid 83.883529 -260.801615)
		(end 83.80476 -260.860794)
		(width 0.088646)
		(layer "In6.Cu")
		(net "M_C_CPU1_SA_DQS_DP<9>")
	)
	(arc
		(start 84.683092 -260.75513)
		(mid 84.533988 -260.803737)
		(end 84.378038 -260.787134)
		(width 0.088646)
		(layer "In6.Cu")
		(net "M_C_CPU1_SA_DQS_DP<9>")
	)
	(arc
		(start 90.88755 -260.75513)
		(mid 90.613321 -260.679205)
		(end 90.336878 -260.746494)
		(width 0.088646)
		(layer "In6.Cu")
		(net "M_C_CPU1_SA_DQS_DP<9>")
	)
	(arc
		(start 91.261946 -260.75513)
		(mid 91.074748 -260.805273)
		(end 90.88755 -260.75513)
		(width 0.088646)
		(layer "In6.Cu")
		(net "M_C_CPU1_SA_DQS_DP<9>")
	)
	(arc
		(start 87.502492 -260.75513)
		(mid 87.315294 -260.805273)
		(end 87.128096 -260.75513)
		(width 0.088646)
		(layer "In6.Cu")
		(net "M_C_CPU1_SA_DQS_DP<9>")
	)
	(arc
		(start 97.083372 -260.487922)
		(mid 97.027156 -260.635336)
		(end 96.915224 -260.746494)
		(width 0.088646)
		(layer "In6.Cu")
		(net "M_C_CPU1_SA_DQS_DP<9>")
	)
	(arc
		(start 90.322146 -260.75513)
		(mid 90.134948 -260.805273)
		(end 89.94775 -260.75513)
		(width 0.088646)
		(layer "In6.Cu")
		(net "M_C_CPU1_SA_DQS_DP<9>")
	)
	(arc
		(start 86.188296 -260.75513)
		(mid 85.905594 -260.679388)
		(end 85.622892 -260.75513)
		(width 0.088646)
		(layer "In6.Cu")
		(net "M_C_CPU1_SA_DQS_DP<9>")
	)
	(arc
		(start 92.76715 -260.75513)
		(mid 92.490337 -260.679294)
		(end 92.211906 -260.749034)
		(width 0.088646)
		(layer "In6.Cu")
		(net "M_C_CPU1_SA_DQS_DP<9>")
	)
	(arc
		(start 96.525842 -260.75513)
		(mid 96.243394 -260.679515)
		(end 95.960946 -260.75513)
		(width 0.088646)
		(layer "In6.Cu")
		(net "M_C_CPU1_SA_DQS_DP<9>")
	)
	(arc
		(start 95.020638 -260.75513)
		(mid 94.83344 -260.805273)
		(end 94.646242 -260.75513)
		(width 0.088646)
		(layer "In6.Cu")
		(net "M_C_CPU1_SA_DQS_DP<9>")
	)
	(arc
		(start 88.442292 -260.75513)
		(mid 88.255094 -260.805273)
		(end 88.067896 -260.75513)
		(width 0.088646)
		(layer "In6.Cu")
		(net "M_C_CPU1_SA_DQS_DP<9>")
	)
	(arc
		(start 92.201492 -260.75513)
		(mid 92.014294 -260.805273)
		(end 91.827096 -260.75513)
		(width 0.088646)
		(layer "In6.Cu")
		(net "M_C_CPU1_SA_DQS_DP<9>")
	)
	(arc
		(start 94.646242 -260.75513)
		(mid 94.363794 -260.679515)
		(end 94.081346 -260.75513)
		(width 0.088646)
		(layer "In6.Cu")
		(net "M_C_CPU1_SA_DQS_DP<9>")
	)
	(segment
		(start 32.375348 -283.00299)
		(end 32.8803 -283.00299)
		(width 0.20066)
		(layer "F.Cu")
		(net "M_C_CPU1_SA_DQS_DP<8>")
	)
	(segment
		(start 32.114236 -282.741878)
		(end 32.375348 -283.00299)
		(width 0.20066)
		(layer "F.Cu")
		(net "M_C_CPU1_SA_DQS_DP<8>")
	)
	(segment
		(start 97.653094 -264.778236)
		(end 97.653348 -265.314176)
		(width 0.20066)
		(layer "F.Cu")
		(net "M_C_CPU1_SA_DQS_DP<8>")
	)
	(segment
		(start 28.398216 -283.427932)
		(end 28.820618 -283.00553)
		(width 0.20066)
		(layer "F.Cu")
		(net "M_C_CPU1_SA_DQS_DP<8>")
	)
	(segment
		(start 29.18079 -283.00553)
		(end 29.450284 -282.736036)
		(width 0.20066)
		(layer "F.Cu")
		(net "M_C_CPU1_SA_DQS_DP<8>")
	)
	(segment
		(start 27.328114 -283.166566)
		(end 27.802586 -283.166566)
		(width 0.20066)
		(layer "F.Cu")
		(net "M_C_CPU1_SA_DQS_DP<8>")
	)
	(segment
		(start 28.063952 -283.427932)
		(end 28.398216 -283.427932)
		(width 0.20066)
		(layer "F.Cu")
		(net "M_C_CPU1_SA_DQS_DP<8>")
	)
	(segment
		(start 31.972758 -282.741878)
		(end 32.114236 -282.741878)
		(width 0.20066)
		(layer "F.Cu")
		(net "M_C_CPU1_SA_DQS_DP<8>")
	)
	(segment
		(start 32.8803 -283.00299)
		(end 33.516316 -283.427932)
		(width 0.20066)
		(layer "F.Cu")
		(net "M_C_CPU1_SA_DQS_DP<8>")
	)
	(segment
		(start 29.89453 -282.741624)
		(end 31.972504 -282.741624)
		(width 0.1016)
		(layer "F.Cu")
		(net "M_C_CPU1_SA_DQS_DP<8>")
	)
	(segment
		(start 33.516316 -283.427932)
		(end 34.120836 -283.427932)
		(width 0.20066)
		(layer "F.Cu")
		(net "M_C_CPU1_SA_DQS_DP<8>")
	)
	(segment
		(start 31.972504 -282.741624)
		(end 31.972758 -282.741878)
		(width 0.1016)
		(layer "F.Cu")
		(net "M_C_CPU1_SA_DQS_DP<8>")
	)
	(segment
		(start 28.820618 -283.00553)
		(end 29.18079 -283.00553)
		(width 0.20066)
		(layer "F.Cu")
		(net "M_C_CPU1_SA_DQS_DP<8>")
	)
	(segment
		(start 34.120836 -283.427932)
		(end 34.382202 -283.166566)
		(width 0.20066)
		(layer "F.Cu")
		(net "M_C_CPU1_SA_DQS_DP<8>")
	)
	(segment
		(start 35.976814 -283.166566)
		(end 34.871914 -283.166566)
		(width 0.20066)
		(layer "F.Cu")
		(net "M_C_CPU1_SA_DQS_DP<8>")
	)
	(segment
		(start 29.647642 -282.736036)
		(end 29.65323 -282.741624)
		(width 0.101854)
		(layer "F.Cu")
		(net "M_C_CPU1_SA_DQS_DP<8>")
	)
	(segment
		(start 29.450284 -282.736036)
		(end 29.647642 -282.736036)
		(width 0.20066)
		(layer "F.Cu")
		(net "M_C_CPU1_SA_DQS_DP<8>")
	)
	(segment
		(start 27.802586 -283.166566)
		(end 28.063952 -283.427932)
		(width 0.20066)
		(layer "F.Cu")
		(net "M_C_CPU1_SA_DQS_DP<8>")
	)
	(segment
		(start 29.65323 -282.741624)
		(end 29.89453 -282.741624)
		(width 0.101854)
		(layer "F.Cu")
		(net "M_C_CPU1_SA_DQS_DP<8>")
	)
	(segment
		(start 34.382202 -283.166566)
		(end 34.871914 -283.166566)
		(width 0.20066)
		(layer "F.Cu")
		(net "M_C_CPU1_SA_DQS_DP<8>")
	)
	(segment
		(start 84.565998 -265.72845)
		(end 83.398868 -266.89558)
		(width 0.088646)
		(layer "In6.Cu")
		(net "M_C_CPU1_SA_DQS_DP<8>")
	)
	(segment
		(start 43.964098 -281.197812)
		(end 43.157648 -281.197812)
		(width 0.18288)
		(layer "In6.Cu")
		(net "M_C_CPU1_SA_DQS_DP<8>")
	)
	(segment
		(start 78.483206 -268.091158)
		(end 70.775576 -271.284192)
		(width 0.18288)
		(layer "In6.Cu")
		(net "M_C_CPU1_SA_DQS_DP<8>")
	)
	(segment
		(start 96.996758 -264.825226)
		(end 96.995996 -264.824718)
		(width 0.088646)
		(layer "In6.Cu")
		(net "M_C_CPU1_SA_DQS_DP<8>")
	)
	(segment
		(start 93.236796 -264.824718)
		(end 93.222064 -264.816082)
		(width 0.088646)
		(layer "In6.Cu")
		(net "M_C_CPU1_SA_DQS_DP<8>")
	)
	(segment
		(start 43.157648 -281.197812)
		(end 41.359328 -282.996132)
		(width 0.18288)
		(layer "In6.Cu")
		(net "M_C_CPU1_SA_DQS_DP<8>")
	)
	(segment
		(start 49.812702 -278.753316)
		(end 48.963834 -279.602184)
		(width 0.18288)
		(layer "In6.Cu")
		(net "M_C_CPU1_SA_DQS_DP<8>")
	)
	(segment
		(start 79.064358 -268.091158)
		(end 78.483206 -268.091158)
		(width 0.18288)
		(layer "In6.Cu")
		(net "M_C_CPU1_SA_DQS_DP<8>")
	)
	(segment
		(start 41.359328 -282.996132)
		(end 40.254428 -282.996132)
		(width 0.18288)
		(layer "In6.Cu")
		(net "M_C_CPU1_SA_DQS_DP<8>")
	)
	(segment
		(start 36.924996 -283.608018)
		(end 36.744656 -283.427678)
		(width 0.18288)
		(layer "In6.Cu")
		(net "M_C_CPU1_SA_DQS_DP<8>")
	)
	(segment
		(start 58.598816 -276.183344)
		(end 55.865268 -276.183344)
		(width 0.18288)
		(layer "In6.Cu")
		(net "M_C_CPU1_SA_DQS_DP<8>")
	)
	(segment
		(start 84.691982 -265.633454)
		(end 84.683092 -265.638534)
		(width 0.088646)
		(layer "In6.Cu")
		(net "M_C_CPU1_SA_DQS_DP<8>")
	)
	(segment
		(start 59.228482 -275.553678)
		(end 58.598816 -276.183344)
		(width 0.18288)
		(layer "In6.Cu")
		(net "M_C_CPU1_SA_DQS_DP<8>")
	)
	(segment
		(start 83.398868 -266.89558)
		(end 83.122262 -266.89558)
		(width 0.088646)
		(layer "In6.Cu")
		(net "M_C_CPU1_SA_DQS_DP<8>")
	)
	(segment
		(start 97.653348 -265.314176)
		(end 97.340674 -265.314176)
		(width 0.088646)
		(layer "In6.Cu")
		(net "M_C_CPU1_SA_DQS_DP<8>")
	)
	(segment
		(start 83.062572 -266.83589)
		(end 83.039204 -266.83589)
		(width 0.088646)
		(layer "In6.Cu")
		(net "M_C_CPU1_SA_DQS_DP<8>")
	)
	(segment
		(start 94.176596 -264.824718)
		(end 94.161864 -264.816082)
		(width 0.088646)
		(layer "In6.Cu")
		(net "M_C_CPU1_SA_DQS_DP<8>")
	)
	(segment
		(start 84.870544 -265.30427)
		(end 84.870544 -265.314176)
		(width 0.088646)
		(layer "In6.Cu")
		(net "M_C_CPU1_SA_DQS_DP<8>")
	)
	(segment
		(start 83.039204 -266.83589)
		(end 82.09534 -266.83589)
		(width 0.18288)
		(layer "In6.Cu")
		(net "M_C_CPU1_SA_DQS_DP<8>")
	)
	(segment
		(start 51.625754 -278.774906)
		(end 51.342544 -278.491696)
		(width 0.18288)
		(layer "In6.Cu")
		(net "M_C_CPU1_SA_DQS_DP<8>")
	)
	(segment
		(start 47.242476 -279.341834)
		(end 46.741334 -279.341834)
		(width 0.18288)
		(layer "In6.Cu")
		(net "M_C_CPU1_SA_DQS_DP<8>")
	)
	(segment
		(start 50.579782 -278.753316)
		(end 49.812702 -278.753316)
		(width 0.18288)
		(layer "In6.Cu")
		(net "M_C_CPU1_SA_DQS_DP<8>")
	)
	(segment
		(start 55.865268 -276.183344)
		(end 54.80812 -277.240492)
		(width 0.18288)
		(layer "In6.Cu")
		(net "M_C_CPU1_SA_DQS_DP<8>")
	)
	(segment
		(start 82.09534 -266.83589)
		(end 79.064358 -268.091158)
		(width 0.18288)
		(layer "In6.Cu")
		(net "M_C_CPU1_SA_DQS_DP<8>")
	)
	(segment
		(start 83.122262 -266.89558)
		(end 83.062572 -266.83589)
		(width 0.088646)
		(layer "In6.Cu")
		(net "M_C_CPU1_SA_DQS_DP<8>")
	)
	(segment
		(start 97.340674 -265.314176)
		(end 97.274888 -265.24839)
		(width 0.088646)
		(layer "In6.Cu")
		(net "M_C_CPU1_SA_DQS_DP<8>")
	)
	(segment
		(start 52.49418 -278.774906)
		(end 51.625754 -278.774906)
		(width 0.18288)
		(layer "In6.Cu")
		(net "M_C_CPU1_SA_DQS_DP<8>")
	)
	(segment
		(start 67.606926 -274.453096)
		(end 65.637918 -274.453096)
		(width 0.18288)
		(layer "In6.Cu")
		(net "M_C_CPU1_SA_DQS_DP<8>")
	)
	(segment
		(start 91.35745 -264.824718)
		(end 91.347036 -264.818622)
		(width 0.088646)
		(layer "In6.Cu")
		(net "M_C_CPU1_SA_DQS_DP<8>")
	)
	(segment
		(start 40.254428 -282.996132)
		(end 39.642542 -283.608018)
		(width 0.18288)
		(layer "In6.Cu")
		(net "M_C_CPU1_SA_DQS_DP<8>")
	)
	(segment
		(start 48.963834 -279.602184)
		(end 47.502826 -279.602184)
		(width 0.18288)
		(layer "In6.Cu")
		(net "M_C_CPU1_SA_DQS_DP<8>")
	)
	(segment
		(start 91.74226 -264.818622)
		(end 91.731846 -264.824718)
		(width 0.088646)
		(layer "In6.Cu")
		(net "M_C_CPU1_SA_DQS_DP<8>")
	)
	(segment
		(start 54.028594 -277.240492)
		(end 52.49418 -278.774906)
		(width 0.18288)
		(layer "In6.Cu")
		(net "M_C_CPU1_SA_DQS_DP<8>")
	)
	(segment
		(start 51.342544 -278.491696)
		(end 50.841402 -278.491696)
		(width 0.18288)
		(layer "In6.Cu")
		(net "M_C_CPU1_SA_DQS_DP<8>")
	)
	(segment
		(start 65.637918 -274.453096)
		(end 64.120268 -275.970746)
		(width 0.18288)
		(layer "In6.Cu")
		(net "M_C_CPU1_SA_DQS_DP<8>")
	)
	(segment
		(start 95.116396 -264.824718)
		(end 95.101664 -264.816082)
		(width 0.088646)
		(layer "In6.Cu")
		(net "M_C_CPU1_SA_DQS_DP<8>")
	)
	(segment
		(start 96.995996 -264.824718)
		(end 96.981264 -264.816082)
		(width 0.088646)
		(layer "In6.Cu")
		(net "M_C_CPU1_SA_DQS_DP<8>")
	)
	(segment
		(start 97.002092 -264.828274)
		(end 96.996758 -264.825226)
		(width 0.088646)
		(layer "In6.Cu")
		(net "M_C_CPU1_SA_DQS_DP<8>")
	)
	(segment
		(start 36.237926 -283.427678)
		(end 35.976814 -283.166566)
		(width 0.18288)
		(layer "In6.Cu")
		(net "M_C_CPU1_SA_DQS_DP<8>")
	)
	(segment
		(start 70.775576 -271.284192)
		(end 67.606926 -274.453096)
		(width 0.18288)
		(layer "In6.Cu")
		(net "M_C_CPU1_SA_DQS_DP<8>")
	)
	(segment
		(start 45.570902 -279.591008)
		(end 43.964098 -281.197812)
		(width 0.18288)
		(layer "In6.Cu")
		(net "M_C_CPU1_SA_DQS_DP<8>")
	)
	(segment
		(start 46.49216 -279.591008)
		(end 45.570902 -279.591008)
		(width 0.18288)
		(layer "In6.Cu")
		(net "M_C_CPU1_SA_DQS_DP<8>")
	)
	(segment
		(start 46.741334 -279.341834)
		(end 46.49216 -279.591008)
		(width 0.18288)
		(layer "In6.Cu")
		(net "M_C_CPU1_SA_DQS_DP<8>")
	)
	(segment
		(start 63.418974 -275.970746)
		(end 63.001906 -275.553678)
		(width 0.18288)
		(layer "In6.Cu")
		(net "M_C_CPU1_SA_DQS_DP<8>")
	)
	(segment
		(start 50.841402 -278.491696)
		(end 50.579782 -278.753316)
		(width 0.18288)
		(layer "In6.Cu")
		(net "M_C_CPU1_SA_DQS_DP<8>")
	)
	(segment
		(start 64.120268 -275.970746)
		(end 63.418974 -275.970746)
		(width 0.18288)
		(layer "In6.Cu")
		(net "M_C_CPU1_SA_DQS_DP<8>")
	)
	(segment
		(start 36.744656 -283.427678)
		(end 36.237926 -283.427678)
		(width 0.18288)
		(layer "In6.Cu")
		(net "M_C_CPU1_SA_DQS_DP<8>")
	)
	(segment
		(start 63.001906 -275.553678)
		(end 59.228482 -275.553678)
		(width 0.18288)
		(layer "In6.Cu")
		(net "M_C_CPU1_SA_DQS_DP<8>")
	)
	(segment
		(start 39.642542 -283.608018)
		(end 36.924996 -283.608018)
		(width 0.18288)
		(layer "In6.Cu")
		(net "M_C_CPU1_SA_DQS_DP<8>")
	)
	(segment
		(start 47.502826 -279.602184)
		(end 47.242476 -279.341834)
		(width 0.18288)
		(layer "In6.Cu")
		(net "M_C_CPU1_SA_DQS_DP<8>")
	)
	(segment
		(start 54.80812 -277.240492)
		(end 54.028594 -277.240492)
		(width 0.18288)
		(layer "In6.Cu")
		(net "M_C_CPU1_SA_DQS_DP<8>")
	)
	(segment
		(start 96.056196 -264.824718)
		(end 96.041464 -264.816082)
		(width 0.088646)
		(layer "In6.Cu")
		(net "M_C_CPU1_SA_DQS_DP<8>")
	)
	(arc
		(start 95.101664 -264.816082)
		(mid 94.825189 -264.748762)
		(end 94.550992 -264.824718)
		(width 0.088646)
		(layer "In6.Cu")
		(net "M_C_CPU1_SA_DQS_DP<8>")
	)
	(arc
		(start 86.092792 -264.824718)
		(mid 85.905594 -264.874861)
		(end 85.718396 -264.824718)
		(width 0.088646)
		(layer "In6.Cu")
		(net "M_C_CPU1_SA_DQS_DP<8>")
	)
	(arc
		(start 90.791792 -264.824718)
		(mid 90.604594 -264.874861)
		(end 90.417396 -264.824718)
		(width 0.088646)
		(layer "In6.Cu")
		(net "M_C_CPU1_SA_DQS_DP<8>")
	)
	(arc
		(start 94.161864 -264.816082)
		(mid 93.885389 -264.748762)
		(end 93.611192 -264.824718)
		(width 0.088646)
		(layer "In6.Cu")
		(net "M_C_CPU1_SA_DQS_DP<8>")
	)
	(arc
		(start 91.731846 -264.824718)
		(mid 91.544648 -264.874861)
		(end 91.35745 -264.824718)
		(width 0.088646)
		(layer "In6.Cu")
		(net "M_C_CPU1_SA_DQS_DP<8>")
	)
	(arc
		(start 87.972392 -264.824718)
		(mid 87.785194 -264.874861)
		(end 87.597996 -264.824718)
		(width 0.088646)
		(layer "In6.Cu")
		(net "M_C_CPU1_SA_DQS_DP<8>")
	)
	(arc
		(start 89.851992 -264.824718)
		(mid 89.664794 -264.874861)
		(end 89.477596 -264.824718)
		(width 0.088646)
		(layer "In6.Cu")
		(net "M_C_CPU1_SA_DQS_DP<8>")
	)
	(arc
		(start 94.550992 -264.824718)
		(mid 94.363794 -264.874861)
		(end 94.176596 -264.824718)
		(width 0.088646)
		(layer "In6.Cu")
		(net "M_C_CPU1_SA_DQS_DP<8>")
	)
	(arc
		(start 92.296996 -264.824718)
		(mid 92.020437 -264.748975)
		(end 91.74226 -264.818622)
		(width 0.088646)
		(layer "In6.Cu")
		(net "M_C_CPU1_SA_DQS_DP<8>")
	)
	(arc
		(start 96.981264 -264.816082)
		(mid 96.704789 -264.748762)
		(end 96.430592 -264.824718)
		(width 0.088646)
		(layer "In6.Cu")
		(net "M_C_CPU1_SA_DQS_DP<8>")
	)
	(arc
		(start 84.683092 -265.638534)
		(mid 84.621597 -265.679653)
		(end 84.565998 -265.72845)
		(width 0.088646)
		(layer "In6.Cu")
		(net "M_C_CPU1_SA_DQS_DP<8>")
	)
	(arc
		(start 97.272094 -265.227562)
		(mid 97.18183 -264.997652)
		(end 97.002092 -264.828274)
		(width 0.088646)
		(layer "In6.Cu")
		(net "M_C_CPU1_SA_DQS_DP<8>")
	)
	(arc
		(start 86.658196 -264.824718)
		(mid 86.375494 -264.748942)
		(end 86.092792 -264.824718)
		(width 0.088646)
		(layer "In6.Cu")
		(net "M_C_CPU1_SA_DQS_DP<8>")
	)
	(arc
		(start 92.671392 -264.824718)
		(mid 92.484194 -264.874861)
		(end 92.296996 -264.824718)
		(width 0.088646)
		(layer "In6.Cu")
		(net "M_C_CPU1_SA_DQS_DP<8>")
	)
	(arc
		(start 93.222064 -264.816082)
		(mid 92.945589 -264.748762)
		(end 92.671392 -264.824718)
		(width 0.088646)
		(layer "In6.Cu")
		(net "M_C_CPU1_SA_DQS_DP<8>")
	)
	(arc
		(start 84.870544 -265.314176)
		(mid 84.822865 -265.497076)
		(end 84.691982 -265.633454)
		(width 0.088646)
		(layer "In6.Cu")
		(net "M_C_CPU1_SA_DQS_DP<8>")
	)
	(arc
		(start 89.477596 -264.824718)
		(mid 89.194894 -264.748942)
		(end 88.912192 -264.824718)
		(width 0.088646)
		(layer "In6.Cu")
		(net "M_C_CPU1_SA_DQS_DP<8>")
	)
	(arc
		(start 93.611192 -264.824718)
		(mid 93.423994 -264.874861)
		(end 93.236796 -264.824718)
		(width 0.088646)
		(layer "In6.Cu")
		(net "M_C_CPU1_SA_DQS_DP<8>")
	)
	(arc
		(start 91.347036 -264.818622)
		(mid 91.068604 -264.748776)
		(end 90.791792 -264.824718)
		(width 0.088646)
		(layer "In6.Cu")
		(net "M_C_CPU1_SA_DQS_DP<8>")
	)
	(arc
		(start 96.041464 -264.816082)
		(mid 95.764989 -264.748762)
		(end 95.490792 -264.824718)
		(width 0.088646)
		(layer "In6.Cu")
		(net "M_C_CPU1_SA_DQS_DP<8>")
	)
	(arc
		(start 85.718396 -264.824718)
		(mid 85.15742 -264.822187)
		(end 84.870544 -265.30427)
		(width 0.088646)
		(layer "In6.Cu")
		(net "M_C_CPU1_SA_DQS_DP<8>")
	)
	(arc
		(start 87.597996 -264.824718)
		(mid 87.315294 -264.748942)
		(end 87.032592 -264.824718)
		(width 0.088646)
		(layer "In6.Cu")
		(net "M_C_CPU1_SA_DQS_DP<8>")
	)
	(arc
		(start 97.274888 -265.24839)
		(mid 97.273587 -265.237963)
		(end 97.272094 -265.227562)
		(width 0.088646)
		(layer "In6.Cu")
		(net "M_C_CPU1_SA_DQS_DP<8>")
	)
	(arc
		(start 88.537796 -264.824718)
		(mid 88.255094 -264.748942)
		(end 87.972392 -264.824718)
		(width 0.088646)
		(layer "In6.Cu")
		(net "M_C_CPU1_SA_DQS_DP<8>")
	)
	(arc
		(start 95.490792 -264.824718)
		(mid 95.303594 -264.874861)
		(end 95.116396 -264.824718)
		(width 0.088646)
		(layer "In6.Cu")
		(net "M_C_CPU1_SA_DQS_DP<8>")
	)
	(arc
		(start 96.430592 -264.824718)
		(mid 96.243394 -264.874861)
		(end 96.056196 -264.824718)
		(width 0.088646)
		(layer "In6.Cu")
		(net "M_C_CPU1_SA_DQS_DP<8>")
	)
	(arc
		(start 87.032592 -264.824718)
		(mid 86.845394 -264.874861)
		(end 86.658196 -264.824718)
		(width 0.088646)
		(layer "In6.Cu")
		(net "M_C_CPU1_SA_DQS_DP<8>")
	)
	(arc
		(start 90.417396 -264.824718)
		(mid 90.134694 -264.748942)
		(end 89.851992 -264.824718)
		(width 0.088646)
		(layer "In6.Cu")
		(net "M_C_CPU1_SA_DQS_DP<8>")
	)
	(arc
		(start 88.912192 -264.824718)
		(mid 88.724994 -264.874861)
		(end 88.537796 -264.824718)
		(width 0.088646)
		(layer "In6.Cu")
		(net "M_C_CPU1_SA_DQS_DP<8>")
	)
	(segment
		(start 32.375348 -292.352984)
		(end 32.8803 -292.352984)
		(width 0.20066)
		(layer "F.Cu")
		(net "M_C_CPU1_SA_DQS_DP<7>")
	)
	(segment
		(start 34.381948 -292.516814)
		(end 34.871914 -292.516814)
		(width 0.20066)
		(layer "F.Cu")
		(net "M_C_CPU1_SA_DQS_DP<7>")
	)
	(segment
		(start 29.647642 -292.08603)
		(end 29.653484 -292.091872)
		(width 0.101854)
		(layer "F.Cu")
		(net "M_C_CPU1_SA_DQS_DP<7>")
	)
	(segment
		(start 32.114236 -292.091872)
		(end 32.375348 -292.352984)
		(width 0.20066)
		(layer "F.Cu")
		(net "M_C_CPU1_SA_DQS_DP<7>")
	)
	(segment
		(start 29.894276 -292.091872)
		(end 31.972758 -292.091872)
		(width 0.1016)
		(layer "F.Cu")
		(net "M_C_CPU1_SA_DQS_DP<7>")
	)
	(segment
		(start 29.653484 -292.091872)
		(end 29.894276 -292.091872)
		(width 0.101854)
		(layer "F.Cu")
		(net "M_C_CPU1_SA_DQS_DP<7>")
	)
	(segment
		(start 32.8803 -292.352984)
		(end 33.516316 -292.777926)
		(width 0.20066)
		(layer "F.Cu")
		(net "M_C_CPU1_SA_DQS_DP<7>")
	)
	(segment
		(start 28.398216 -292.777926)
		(end 28.820618 -292.355524)
		(width 0.20066)
		(layer "F.Cu")
		(net "M_C_CPU1_SA_DQS_DP<7>")
	)
	(segment
		(start 29.18079 -292.355524)
		(end 29.450284 -292.08603)
		(width 0.20066)
		(layer "F.Cu")
		(net "M_C_CPU1_SA_DQS_DP<7>")
	)
	(segment
		(start 35.976814 -292.516814)
		(end 34.871914 -292.516814)
		(width 0.20066)
		(layer "F.Cu")
		(net "M_C_CPU1_SA_DQS_DP<7>")
	)
	(segment
		(start 28.063952 -292.777926)
		(end 28.398216 -292.777926)
		(width 0.20066)
		(layer "F.Cu")
		(net "M_C_CPU1_SA_DQS_DP<7>")
	)
	(segment
		(start 27.328114 -292.516814)
		(end 27.80284 -292.516814)
		(width 0.20066)
		(layer "F.Cu")
		(net "M_C_CPU1_SA_DQS_DP<7>")
	)
	(segment
		(start 33.516316 -292.777926)
		(end 34.120836 -292.777926)
		(width 0.20066)
		(layer "F.Cu")
		(net "M_C_CPU1_SA_DQS_DP<7>")
	)
	(segment
		(start 31.972758 -292.091872)
		(end 32.114236 -292.091872)
		(width 0.20066)
		(layer "F.Cu")
		(net "M_C_CPU1_SA_DQS_DP<7>")
	)
	(segment
		(start 34.120836 -292.777926)
		(end 34.381948 -292.516814)
		(width 0.20066)
		(layer "F.Cu")
		(net "M_C_CPU1_SA_DQS_DP<7>")
	)
	(segment
		(start 27.80284 -292.516814)
		(end 28.063952 -292.777926)
		(width 0.20066)
		(layer "F.Cu")
		(net "M_C_CPU1_SA_DQS_DP<7>")
	)
	(segment
		(start 28.820618 -292.355524)
		(end 29.18079 -292.355524)
		(width 0.20066)
		(layer "F.Cu")
		(net "M_C_CPU1_SA_DQS_DP<7>")
	)
	(segment
		(start 93.424248 -267.219938)
		(end 93.423994 -267.755878)
		(width 0.20066)
		(layer "F.Cu")
		(net "M_C_CPU1_SA_DQS_DP<7>")
	)
	(segment
		(start 29.450284 -292.08603)
		(end 29.647642 -292.08603)
		(width 0.20066)
		(layer "F.Cu")
		(net "M_C_CPU1_SA_DQS_DP<7>")
	)
	(segment
		(start 45.830744 -292.356794)
		(end 45.243496 -291.769546)
		(width 0.18288)
		(layer "In4.Cu")
		(net "M_C_CPU1_SA_DQS_DP<7>")
	)
	(segment
		(start 50.609246 -291.504878)
		(end 49.953418 -291.504878)
		(width 0.18288)
		(layer "In4.Cu")
		(net "M_C_CPU1_SA_DQS_DP<7>")
	)
	(segment
		(start 77.563726 -272.632678)
		(end 77.175614 -273.02079)
		(width 0.18288)
		(layer "In4.Cu")
		(net "M_C_CPU1_SA_DQS_DP<7>")
	)
	(segment
		(start 77.175614 -273.196812)
		(end 76.787756 -273.58467)
		(width 0.18288)
		(layer "In4.Cu")
		(net "M_C_CPU1_SA_DQS_DP<7>")
	)
	(segment
		(start 78.127606 -272.24482)
		(end 77.739748 -272.632678)
		(width 0.18288)
		(layer "In4.Cu")
		(net "M_C_CPU1_SA_DQS_DP<7>")
	)
	(segment
		(start 55.037228 -291.765482)
		(end 53.098954 -291.765482)
		(width 0.18288)
		(layer "In4.Cu")
		(net "M_C_CPU1_SA_DQS_DP<7>")
	)
	(segment
		(start 57.147714 -291.726112)
		(end 56.232044 -292.105842)
		(width 0.18288)
		(layer "In4.Cu")
		(net "M_C_CPU1_SA_DQS_DP<7>")
	)
	(segment
		(start 79.46771 -270.728694)
		(end 79.079598 -271.116806)
		(width 0.18288)
		(layer "In4.Cu")
		(net "M_C_CPU1_SA_DQS_DP<7>")
	)
	(segment
		(start 47.153068 -292.091872)
		(end 46.768766 -292.091872)
		(width 0.18288)
		(layer "In4.Cu")
		(net "M_C_CPU1_SA_DQS_DP<7>")
	)
	(segment
		(start 80.419702 -269.776702)
		(end 80.03159 -270.164814)
		(width 0.18288)
		(layer "In4.Cu")
		(net "M_C_CPU1_SA_DQS_DP<7>")
	)
	(segment
		(start 72.415654 -277.956772)
		(end 72.027796 -278.34463)
		(width 0.18288)
		(layer "In4.Cu")
		(net "M_C_CPU1_SA_DQS_DP<7>")
	)
	(segment
		(start 66.906902 -285.769812)
		(end 66.62928 -285.88462)
		(width 0.18288)
		(layer "In4.Cu")
		(net "M_C_CPU1_SA_DQS_DP<7>")
	)
	(segment
		(start 66.62928 -285.88462)
		(end 66.385694 -286.128206)
		(width 0.18288)
		(layer "In4.Cu")
		(net "M_C_CPU1_SA_DQS_DP<7>")
	)
	(segment
		(start 70.755256 -279.616916)
		(end 69.11721 -283.57322)
		(width 0.18288)
		(layer "In4.Cu")
		(net "M_C_CPU1_SA_DQS_DP<7>")
	)
	(segment
		(start 58.652918 -290.920678)
		(end 57.147714 -291.726112)
		(width 0.18288)
		(layer "In4.Cu")
		(net "M_C_CPU1_SA_DQS_DP<7>")
	)
	(segment
		(start 80.983582 -269.212822)
		(end 80.983582 -269.388844)
		(width 0.18288)
		(layer "In4.Cu")
		(net "M_C_CPU1_SA_DQS_DP<7>")
	)
	(segment
		(start 73.367646 -277.00478)
		(end 72.979788 -277.392638)
		(width 0.18288)
		(layer "In4.Cu")
		(net "M_C_CPU1_SA_DQS_DP<7>")
	)
	(segment
		(start 65.712086 -286.782764)
		(end 65.5066 -286.987996)
		(width 0.18288)
		(layer "In4.Cu")
		(net "M_C_CPU1_SA_DQS_DP<7>")
	)
	(segment
		(start 49.953418 -291.504878)
		(end 49.092104 -292.366192)
		(width 0.18288)
		(layer "In4.Cu")
		(net "M_C_CPU1_SA_DQS_DP<7>")
	)
	(segment
		(start 65.96761 -286.128206)
		(end 65.712086 -286.38373)
		(width 0.18288)
		(layer "In4.Cu")
		(net "M_C_CPU1_SA_DQS_DP<7>")
	)
	(segment
		(start 76.611734 -273.58467)
		(end 76.223622 -273.972782)
		(width 0.18288)
		(layer "In4.Cu")
		(net "M_C_CPU1_SA_DQS_DP<7>")
	)
	(segment
		(start 78.515718 -271.680686)
		(end 78.127606 -272.068798)
		(width 0.18288)
		(layer "In4.Cu")
		(net "M_C_CPU1_SA_DQS_DP<7>")
	)
	(segment
		(start 53.098954 -291.765482)
		(end 52.49037 -291.513514)
		(width 0.18288)
		(layer "In4.Cu")
		(net "M_C_CPU1_SA_DQS_DP<7>")
	)
	(segment
		(start 79.643732 -270.728694)
		(end 79.46771 -270.728694)
		(width 0.18288)
		(layer "In4.Cu")
		(net "M_C_CPU1_SA_DQS_DP<7>")
	)
	(segment
		(start 83.519772 -268.50594)
		(end 83.496404 -268.50594)
		(width 0.088646)
		(layer "In4.Cu")
		(net "M_C_CPU1_SA_DQS_DP<7>")
	)
	(segment
		(start 66.930524 -285.759906)
		(end 66.906648 -285.769812)
		(width 0.18288)
		(layer "In4.Cu")
		(net "M_C_CPU1_SA_DQS_DP<7>")
	)
	(segment
		(start 65.5066 -286.987996)
		(end 64.229996 -287.517078)
		(width 0.18288)
		(layer "In4.Cu")
		(net "M_C_CPU1_SA_DQS_DP<7>")
	)
	(segment
		(start 81.371694 -268.82471)
		(end 80.983582 -269.212822)
		(width 0.18288)
		(layer "In4.Cu")
		(net "M_C_CPU1_SA_DQS_DP<7>")
	)
	(segment
		(start 74.319638 -276.052788)
		(end 73.93178 -276.440646)
		(width 0.18288)
		(layer "In4.Cu")
		(net "M_C_CPU1_SA_DQS_DP<7>")
	)
	(segment
		(start 72.979788 -277.392638)
		(end 72.803766 -277.392638)
		(width 0.18288)
		(layer "In4.Cu")
		(net "M_C_CPU1_SA_DQS_DP<7>")
	)
	(segment
		(start 78.127606 -272.068798)
		(end 78.127606 -272.24482)
		(width 0.18288)
		(layer "In4.Cu")
		(net "M_C_CPU1_SA_DQS_DP<7>")
	)
	(segment
		(start 51.524916 -291.513514)
		(end 51.253136 -291.241734)
		(width 0.18288)
		(layer "In4.Cu")
		(net "M_C_CPU1_SA_DQS_DP<7>")
	)
	(segment
		(start 66.385694 -286.128206)
		(end 65.96761 -286.128206)
		(width 0.18288)
		(layer "In4.Cu")
		(net "M_C_CPU1_SA_DQS_DP<7>")
	)
	(segment
		(start 74.319638 -275.876766)
		(end 74.319638 -276.052788)
		(width 0.18288)
		(layer "In4.Cu")
		(net "M_C_CPU1_SA_DQS_DP<7>")
	)
	(segment
		(start 89.011506 -267.268452)
		(end 89.007696 -267.266166)
		(width 0.088646)
		(layer "In4.Cu")
		(net "M_C_CPU1_SA_DQS_DP<7>")
	)
	(segment
		(start 76.223622 -274.148804)
		(end 75.835764 -274.536662)
		(width 0.18288)
		(layer "In4.Cu")
		(net "M_C_CPU1_SA_DQS_DP<7>")
	)
	(segment
		(start 41.304464 -292.26129)
		(end 39.398448 -293.05123)
		(width 0.18288)
		(layer "In4.Cu")
		(net "M_C_CPU1_SA_DQS_DP<7>")
	)
	(segment
		(start 73.367646 -276.828758)
		(end 73.367646 -277.00478)
		(width 0.18288)
		(layer "In4.Cu")
		(net "M_C_CPU1_SA_DQS_DP<7>")
	)
	(segment
		(start 76.787756 -273.58467)
		(end 76.611734 -273.58467)
		(width 0.18288)
		(layer "In4.Cu")
		(net "M_C_CPU1_SA_DQS_DP<7>")
	)
	(segment
		(start 78.69174 -271.680686)
		(end 78.515718 -271.680686)
		(width 0.18288)
		(layer "In4.Cu")
		(net "M_C_CPU1_SA_DQS_DP<7>")
	)
	(segment
		(start 84.965286 -267.190982)
		(end 84.581492 -267.190982)
		(width 0.088646)
		(layer "In4.Cu")
		(net "M_C_CPU1_SA_DQS_DP<7>")
	)
	(segment
		(start 86.562946 -267.265912)
		(end 86.5632 -267.266674)
		(width 0.088646)
		(layer "In4.Cu")
		(net "M_C_CPU1_SA_DQS_DP<7>")
	)
	(segment
		(start 37.026088 -293.05123)
		(end 36.765738 -292.79088)
		(width 0.18288)
		(layer "In4.Cu")
		(net "M_C_CPU1_SA_DQS_DP<7>")
	)
	(segment
		(start 72.803766 -277.392638)
		(end 72.415654 -277.78075)
		(width 0.18288)
		(layer "In4.Cu")
		(net "M_C_CPU1_SA_DQS_DP<7>")
	)
	(segment
		(start 79.079598 -271.292828)
		(end 78.69174 -271.680686)
		(width 0.18288)
		(layer "In4.Cu")
		(net "M_C_CPU1_SA_DQS_DP<7>")
	)
	(segment
		(start 55.858918 -292.105842)
		(end 55.037228 -291.765482)
		(width 0.18288)
		(layer "In4.Cu")
		(net "M_C_CPU1_SA_DQS_DP<7>")
	)
	(segment
		(start 89.950036 -267.267944)
		(end 89.947496 -267.26642)
		(width 0.088646)
		(layer "In4.Cu")
		(net "M_C_CPU1_SA_DQS_DP<7>")
	)
	(segment
		(start 65.712086 -286.38373)
		(end 65.712086 -286.782764)
		(width 0.18288)
		(layer "In4.Cu")
		(net "M_C_CPU1_SA_DQS_DP<7>")
	)
	(segment
		(start 80.03159 -270.164814)
		(end 80.03159 -270.340836)
		(width 0.18288)
		(layer "In4.Cu")
		(net "M_C_CPU1_SA_DQS_DP<7>")
	)
	(segment
		(start 80.983582 -269.388844)
		(end 80.595724 -269.776702)
		(width 0.18288)
		(layer "In4.Cu")
		(net "M_C_CPU1_SA_DQS_DP<7>")
	)
	(segment
		(start 83.795362 -267.977112)
		(end 83.795362 -268.476984)
		(width 0.088646)
		(layer "In4.Cu")
		(net "M_C_CPU1_SA_DQS_DP<7>")
	)
	(segment
		(start 83.579462 -268.56563)
		(end 83.519772 -268.50594)
		(width 0.088646)
		(layer "In4.Cu")
		(net "M_C_CPU1_SA_DQS_DP<7>")
	)
	(segment
		(start 81.866486 -268.50594)
		(end 81.547716 -268.82471)
		(width 0.18288)
		(layer "In4.Cu")
		(net "M_C_CPU1_SA_DQS_DP<7>")
	)
	(segment
		(start 71.463662 -278.908764)
		(end 70.755256 -279.616916)
		(width 0.18288)
		(layer "In4.Cu")
		(net "M_C_CPU1_SA_DQS_DP<7>")
	)
	(segment
		(start 91.831668 -267.26896)
		(end 91.827096 -267.26642)
		(width 0.088646)
		(layer "In4.Cu")
		(net "M_C_CPU1_SA_DQS_DP<7>")
	)
	(segment
		(start 71.851774 -278.34463)
		(end 71.463662 -278.732742)
		(width 0.18288)
		(layer "In4.Cu")
		(net "M_C_CPU1_SA_DQS_DP<7>")
	)
	(segment
		(start 75.835764 -274.536662)
		(end 75.659742 -274.536662)
		(width 0.18288)
		(layer "In4.Cu")
		(net "M_C_CPU1_SA_DQS_DP<7>")
	)
	(segment
		(start 46.768766 -292.091872)
		(end 46.503844 -292.356794)
		(width 0.18288)
		(layer "In4.Cu")
		(net "M_C_CPU1_SA_DQS_DP<7>")
	)
	(segment
		(start 44.246546 -291.769546)
		(end 43.754802 -292.26129)
		(width 0.18288)
		(layer "In4.Cu")
		(net "M_C_CPU1_SA_DQS_DP<7>")
	)
	(segment
		(start 81.547716 -268.82471)
		(end 81.371694 -268.82471)
		(width 0.18288)
		(layer "In4.Cu")
		(net "M_C_CPU1_SA_DQS_DP<7>")
	)
	(segment
		(start 66.906648 -285.769812)
		(end 66.906902 -285.769812)
		(width 0.18288)
		(layer "In4.Cu")
		(net "M_C_CPU1_SA_DQS_DP<7>")
	)
	(segment
		(start 36.25088 -292.79088)
		(end 35.976814 -292.516814)
		(width 0.18288)
		(layer "In4.Cu")
		(net "M_C_CPU1_SA_DQS_DP<7>")
	)
	(segment
		(start 80.03159 -270.340836)
		(end 79.643732 -270.728694)
		(width 0.18288)
		(layer "In4.Cu")
		(net "M_C_CPU1_SA_DQS_DP<7>")
	)
	(segment
		(start 51.253136 -291.241734)
		(end 50.87239 -291.241734)
		(width 0.18288)
		(layer "In4.Cu")
		(net "M_C_CPU1_SA_DQS_DP<7>")
	)
	(segment
		(start 69.11721 -283.57322)
		(end 66.930524 -285.759906)
		(width 0.18288)
		(layer "In4.Cu")
		(net "M_C_CPU1_SA_DQS_DP<7>")
	)
	(segment
		(start 79.079598 -271.116806)
		(end 79.079598 -271.292828)
		(width 0.18288)
		(layer "In4.Cu")
		(net "M_C_CPU1_SA_DQS_DP<7>")
	)
	(segment
		(start 83.706716 -268.56563)
		(end 83.579462 -268.56563)
		(width 0.088646)
		(layer "In4.Cu")
		(net "M_C_CPU1_SA_DQS_DP<7>")
	)
	(segment
		(start 73.93178 -276.440646)
		(end 73.755758 -276.440646)
		(width 0.18288)
		(layer "In4.Cu")
		(net "M_C_CPU1_SA_DQS_DP<7>")
	)
	(segment
		(start 80.595724 -269.776702)
		(end 80.419702 -269.776702)
		(width 0.18288)
		(layer "In4.Cu")
		(net "M_C_CPU1_SA_DQS_DP<7>")
	)
	(segment
		(start 61.19622 -288.377376)
		(end 58.652918 -290.920678)
		(width 0.18288)
		(layer "In4.Cu")
		(net "M_C_CPU1_SA_DQS_DP<7>")
	)
	(segment
		(start 75.27163 -274.924774)
		(end 75.27163 -275.100796)
		(width 0.18288)
		(layer "In4.Cu")
		(net "M_C_CPU1_SA_DQS_DP<7>")
	)
	(segment
		(start 62.776862 -288.377376)
		(end 61.19622 -288.377376)
		(width 0.18288)
		(layer "In4.Cu")
		(net "M_C_CPU1_SA_DQS_DP<7>")
	)
	(segment
		(start 77.739748 -272.632678)
		(end 77.563726 -272.632678)
		(width 0.18288)
		(layer "In4.Cu")
		(net "M_C_CPU1_SA_DQS_DP<7>")
	)
	(segment
		(start 56.232044 -292.105842)
		(end 55.858918 -292.105842)
		(width 0.18288)
		(layer "In4.Cu")
		(net "M_C_CPU1_SA_DQS_DP<7>")
	)
	(segment
		(start 36.765738 -292.79088)
		(end 36.25088 -292.79088)
		(width 0.18288)
		(layer "In4.Cu")
		(net "M_C_CPU1_SA_DQS_DP<7>")
	)
	(segment
		(start 83.795362 -268.476984)
		(end 83.706716 -268.56563)
		(width 0.088646)
		(layer "In4.Cu")
		(net "M_C_CPU1_SA_DQS_DP<7>")
	)
	(segment
		(start 72.027796 -278.34463)
		(end 71.851774 -278.34463)
		(width 0.18288)
		(layer "In4.Cu")
		(net "M_C_CPU1_SA_DQS_DP<7>")
	)
	(segment
		(start 90.891868 -267.26896)
		(end 90.887296 -267.26642)
		(width 0.088646)
		(layer "In4.Cu")
		(net "M_C_CPU1_SA_DQS_DP<7>")
	)
	(segment
		(start 64.229996 -287.517078)
		(end 63.63716 -287.517078)
		(width 0.18288)
		(layer "In4.Cu")
		(net "M_C_CPU1_SA_DQS_DP<7>")
	)
	(segment
		(start 75.659742 -274.536662)
		(end 75.27163 -274.924774)
		(width 0.18288)
		(layer "In4.Cu")
		(net "M_C_CPU1_SA_DQS_DP<7>")
	)
	(segment
		(start 90.887296 -267.26642)
		(end 90.87993 -267.262102)
		(width 0.088646)
		(layer "In4.Cu")
		(net "M_C_CPU1_SA_DQS_DP<7>")
	)
	(segment
		(start 47.427388 -292.366192)
		(end 47.153068 -292.091872)
		(width 0.18288)
		(layer "In4.Cu")
		(net "M_C_CPU1_SA_DQS_DP<7>")
	)
	(segment
		(start 45.243496 -291.769546)
		(end 44.246546 -291.769546)
		(width 0.18288)
		(layer "In4.Cu")
		(net "M_C_CPU1_SA_DQS_DP<7>")
	)
	(segment
		(start 92.80017 -267.284962)
		(end 92.766896 -267.26642)
		(width 0.088646)
		(layer "In4.Cu")
		(net "M_C_CPU1_SA_DQS_DP<7>")
	)
	(segment
		(start 74.70775 -275.488654)
		(end 74.319638 -275.876766)
		(width 0.18288)
		(layer "In4.Cu")
		(net "M_C_CPU1_SA_DQS_DP<7>")
	)
	(segment
		(start 83.496404 -268.50594)
		(end 81.866486 -268.50594)
		(width 0.18288)
		(layer "In4.Cu")
		(net "M_C_CPU1_SA_DQS_DP<7>")
	)
	(segment
		(start 39.398448 -293.05123)
		(end 37.026088 -293.05123)
		(width 0.18288)
		(layer "In4.Cu")
		(net "M_C_CPU1_SA_DQS_DP<7>")
	)
	(segment
		(start 73.755758 -276.440646)
		(end 73.367646 -276.828758)
		(width 0.18288)
		(layer "In4.Cu")
		(net "M_C_CPU1_SA_DQS_DP<7>")
	)
	(segment
		(start 74.883772 -275.488654)
		(end 74.70775 -275.488654)
		(width 0.18288)
		(layer "In4.Cu")
		(net "M_C_CPU1_SA_DQS_DP<7>")
	)
	(segment
		(start 76.223622 -273.972782)
		(end 76.223622 -274.148804)
		(width 0.18288)
		(layer "In4.Cu")
		(net "M_C_CPU1_SA_DQS_DP<7>")
	)
	(segment
		(start 50.87239 -291.241734)
		(end 50.609246 -291.504878)
		(width 0.18288)
		(layer "In4.Cu")
		(net "M_C_CPU1_SA_DQS_DP<7>")
	)
	(segment
		(start 91.827096 -267.26642)
		(end 91.81973 -267.262102)
		(width 0.088646)
		(layer "In4.Cu")
		(net "M_C_CPU1_SA_DQS_DP<7>")
	)
	(segment
		(start 63.63716 -287.517078)
		(end 62.776862 -288.377376)
		(width 0.18288)
		(layer "In4.Cu")
		(net "M_C_CPU1_SA_DQS_DP<7>")
	)
	(segment
		(start 84.581492 -267.190982)
		(end 83.795362 -267.977112)
		(width 0.088646)
		(layer "In4.Cu")
		(net "M_C_CPU1_SA_DQS_DP<7>")
	)
	(segment
		(start 92.766896 -267.26642)
		(end 92.75953 -267.262102)
		(width 0.088646)
		(layer "In4.Cu")
		(net "M_C_CPU1_SA_DQS_DP<7>")
	)
	(segment
		(start 72.415654 -277.78075)
		(end 72.415654 -277.956772)
		(width 0.18288)
		(layer "In4.Cu")
		(net "M_C_CPU1_SA_DQS_DP<7>")
	)
	(segment
		(start 43.754802 -292.26129)
		(end 41.304464 -292.26129)
		(width 0.18288)
		(layer "In4.Cu")
		(net "M_C_CPU1_SA_DQS_DP<7>")
	)
	(segment
		(start 46.503844 -292.356794)
		(end 45.830744 -292.356794)
		(width 0.18288)
		(layer "In4.Cu")
		(net "M_C_CPU1_SA_DQS_DP<7>")
	)
	(segment
		(start 75.27163 -275.100796)
		(end 74.883772 -275.488654)
		(width 0.18288)
		(layer "In4.Cu")
		(net "M_C_CPU1_SA_DQS_DP<7>")
	)
	(segment
		(start 52.49037 -291.513514)
		(end 51.524916 -291.513514)
		(width 0.18288)
		(layer "In4.Cu")
		(net "M_C_CPU1_SA_DQS_DP<7>")
	)
	(segment
		(start 49.092104 -292.366192)
		(end 47.427388 -292.366192)
		(width 0.18288)
		(layer "In4.Cu")
		(net "M_C_CPU1_SA_DQS_DP<7>")
	)
	(segment
		(start 77.175614 -273.02079)
		(end 77.175614 -273.196812)
		(width 0.18288)
		(layer "In4.Cu")
		(net "M_C_CPU1_SA_DQS_DP<7>")
	)
	(segment
		(start 71.463662 -278.732742)
		(end 71.463662 -278.908764)
		(width 0.18288)
		(layer "In4.Cu")
		(net "M_C_CPU1_SA_DQS_DP<7>")
	)
	(arc
		(start 92.75953 -267.262102)
		(mid 92.480069 -267.190665)
		(end 92.201746 -267.26642)
		(width 0.088646)
		(layer "In4.Cu")
		(net "M_C_CPU1_SA_DQS_DP<7>")
	)
	(arc
		(start 89.007696 -267.266166)
		(mid 88.724994 -267.190424)
		(end 88.442292 -267.266166)
		(width 0.088646)
		(layer "In4.Cu")
		(net "M_C_CPU1_SA_DQS_DP<7>")
	)
	(arc
		(start 85.247988 -267.266674)
		(mid 85.111618 -267.210221)
		(end 84.965286 -267.190982)
		(width 0.088646)
		(layer "In4.Cu")
		(net "M_C_CPU1_SA_DQS_DP<7>")
	)
	(arc
		(start 91.81973 -267.262102)
		(mid 91.540269 -267.190665)
		(end 91.261946 -267.26642)
		(width 0.088646)
		(layer "In4.Cu")
		(net "M_C_CPU1_SA_DQS_DP<7>")
	)
	(arc
		(start 91.261946 -267.26642)
		(mid 91.077252 -267.316521)
		(end 90.891868 -267.26896)
		(width 0.088646)
		(layer "In4.Cu")
		(net "M_C_CPU1_SA_DQS_DP<7>")
	)
	(arc
		(start 88.067896 -267.266166)
		(mid 87.785194 -267.190424)
		(end 87.502492 -267.266166)
		(width 0.088646)
		(layer "In4.Cu")
		(net "M_C_CPU1_SA_DQS_DP<7>")
	)
	(arc
		(start 92.201746 -267.26642)
		(mid 92.017052 -267.316521)
		(end 91.831668 -267.26896)
		(width 0.088646)
		(layer "In4.Cu")
		(net "M_C_CPU1_SA_DQS_DP<7>")
	)
	(arc
		(start 89.382346 -267.26642)
		(mid 89.197196 -267.316524)
		(end 89.011506 -267.268452)
		(width 0.088646)
		(layer "In4.Cu")
		(net "M_C_CPU1_SA_DQS_DP<7>")
	)
	(arc
		(start 85.6234 -267.266674)
		(mid 85.435694 -267.317003)
		(end 85.247988 -267.266674)
		(width 0.088646)
		(layer "In4.Cu")
		(net "M_C_CPU1_SA_DQS_DP<7>")
	)
	(arc
		(start 93.423994 -267.755878)
		(mid 93.128391 -267.498814)
		(end 92.80017 -267.284962)
		(width 0.088646)
		(layer "In4.Cu")
		(net "M_C_CPU1_SA_DQS_DP<7>")
	)
	(arc
		(start 87.502492 -267.266166)
		(mid 87.315294 -267.316309)
		(end 87.128096 -267.266166)
		(width 0.088646)
		(layer "In4.Cu")
		(net "M_C_CPU1_SA_DQS_DP<7>")
	)
	(arc
		(start 87.128096 -267.266166)
		(mid 86.845567 -267.190424)
		(end 86.562946 -267.265912)
		(width 0.088646)
		(layer "In4.Cu")
		(net "M_C_CPU1_SA_DQS_DP<7>")
	)
	(arc
		(start 90.322146 -267.26642)
		(mid 90.136285 -267.316653)
		(end 89.950036 -267.267944)
		(width 0.088646)
		(layer "In4.Cu")
		(net "M_C_CPU1_SA_DQS_DP<7>")
	)
	(arc
		(start 90.87993 -267.262102)
		(mid 90.600469 -267.190665)
		(end 90.322146 -267.26642)
		(width 0.088646)
		(layer "In4.Cu")
		(net "M_C_CPU1_SA_DQS_DP<7>")
	)
	(arc
		(start 86.187788 -267.266674)
		(mid 85.905594 -267.191118)
		(end 85.6234 -267.266674)
		(width 0.088646)
		(layer "In4.Cu")
		(net "M_C_CPU1_SA_DQS_DP<7>")
	)
	(arc
		(start 86.5632 -267.266674)
		(mid 86.375494 -267.317003)
		(end 86.187788 -267.266674)
		(width 0.088646)
		(layer "In4.Cu")
		(net "M_C_CPU1_SA_DQS_DP<7>")
	)
	(arc
		(start 88.442292 -267.266166)
		(mid 88.255094 -267.316309)
		(end 88.067896 -267.266166)
		(width 0.088646)
		(layer "In4.Cu")
		(net "M_C_CPU1_SA_DQS_DP<7>")
	)
	(arc
		(start 89.947496 -267.26642)
		(mid 89.664938 -267.190771)
		(end 89.382346 -267.26642)
		(width 0.088646)
		(layer "In4.Cu")
		(net "M_C_CPU1_SA_DQS_DP<7>")
	)
	(segment
		(start 32.8803 -301.702978)
		(end 33.516316 -302.12792)
		(width 0.20066)
		(layer "F.Cu")
		(net "M_C_CPU1_SA_DQS_DP<6>")
	)
	(segment
		(start 35.976814 -301.866808)
		(end 34.871914 -301.866808)
		(width 0.20066)
		(layer "F.Cu")
		(net "M_C_CPU1_SA_DQS_DP<6>")
	)
	(segment
		(start 32.375348 -301.702978)
		(end 32.8803 -301.702978)
		(width 0.20066)
		(layer "F.Cu")
		(net "M_C_CPU1_SA_DQS_DP<6>")
	)
	(segment
		(start 28.820618 -301.705518)
		(end 29.18079 -301.705518)
		(width 0.20066)
		(layer "F.Cu")
		(net "M_C_CPU1_SA_DQS_DP<6>")
	)
	(segment
		(start 29.653484 -301.441866)
		(end 29.894276 -301.441866)
		(width 0.101854)
		(layer "F.Cu")
		(net "M_C_CPU1_SA_DQS_DP<6>")
	)
	(segment
		(start 29.18079 -301.705518)
		(end 29.450284 -301.436024)
		(width 0.20066)
		(layer "F.Cu")
		(net "M_C_CPU1_SA_DQS_DP<6>")
	)
	(segment
		(start 29.450284 -301.436024)
		(end 29.647642 -301.436024)
		(width 0.20066)
		(layer "F.Cu")
		(net "M_C_CPU1_SA_DQS_DP<6>")
	)
	(segment
		(start 29.647642 -301.436024)
		(end 29.653484 -301.441866)
		(width 0.101854)
		(layer "F.Cu")
		(net "M_C_CPU1_SA_DQS_DP<6>")
	)
	(segment
		(start 27.328114 -301.866808)
		(end 27.80284 -301.866808)
		(width 0.20066)
		(layer "F.Cu")
		(net "M_C_CPU1_SA_DQS_DP<6>")
	)
	(segment
		(start 28.063952 -302.12792)
		(end 28.398216 -302.12792)
		(width 0.20066)
		(layer "F.Cu")
		(net "M_C_CPU1_SA_DQS_DP<6>")
	)
	(segment
		(start 32.114236 -301.441866)
		(end 32.375348 -301.702978)
		(width 0.20066)
		(layer "F.Cu")
		(net "M_C_CPU1_SA_DQS_DP<6>")
	)
	(segment
		(start 96.713294 -269.66164)
		(end 96.713548 -270.19758)
		(width 0.20066)
		(layer "F.Cu")
		(net "M_C_CPU1_SA_DQS_DP<6>")
	)
	(segment
		(start 34.381948 -301.866808)
		(end 34.871914 -301.866808)
		(width 0.20066)
		(layer "F.Cu")
		(net "M_C_CPU1_SA_DQS_DP<6>")
	)
	(segment
		(start 33.516316 -302.12792)
		(end 34.120836 -302.12792)
		(width 0.20066)
		(layer "F.Cu")
		(net "M_C_CPU1_SA_DQS_DP<6>")
	)
	(segment
		(start 31.972758 -301.441866)
		(end 32.114236 -301.441866)
		(width 0.20066)
		(layer "F.Cu")
		(net "M_C_CPU1_SA_DQS_DP<6>")
	)
	(segment
		(start 27.80284 -301.866808)
		(end 28.063952 -302.12792)
		(width 0.20066)
		(layer "F.Cu")
		(net "M_C_CPU1_SA_DQS_DP<6>")
	)
	(segment
		(start 28.398216 -302.12792)
		(end 28.820618 -301.705518)
		(width 0.20066)
		(layer "F.Cu")
		(net "M_C_CPU1_SA_DQS_DP<6>")
	)
	(segment
		(start 29.894276 -301.441866)
		(end 31.972758 -301.441866)
		(width 0.1016)
		(layer "F.Cu")
		(net "M_C_CPU1_SA_DQS_DP<6>")
	)
	(segment
		(start 34.120836 -302.12792)
		(end 34.381948 -301.866808)
		(width 0.20066)
		(layer "F.Cu")
		(net "M_C_CPU1_SA_DQS_DP<6>")
	)
	(segment
		(start 73.631806 -278.01316)
		(end 73.243694 -278.401526)
		(width 0.18288)
		(layer "In6.Cu")
		(net "M_C_CPU1_SA_DQS_DP<6>")
	)
	(segment
		(start 75.535536 -276.108668)
		(end 75.147424 -276.497034)
		(width 0.18288)
		(layer "In6.Cu")
		(net "M_C_CPU1_SA_DQS_DP<6>")
	)
	(segment
		(start 95.490792 -269.708122)
		(end 95.490792 -269.707868)
		(width 0.088646)
		(layer "In6.Cu")
		(net "M_C_CPU1_SA_DQS_DP<6>")
	)
	(segment
		(start 65.13957 -284.710124)
		(end 64.751458 -285.098236)
		(width 0.18288)
		(layer "In6.Cu")
		(net "M_C_CPU1_SA_DQS_DP<6>")
	)
	(segment
		(start 71.728076 -279.917652)
		(end 71.339964 -280.306018)
		(width 0.18288)
		(layer "In6.Cu")
		(net "M_C_CPU1_SA_DQS_DP<6>")
	)
	(segment
		(start 56.949848 -288.811208)
		(end 55.873904 -289.256978)
		(width 0.18288)
		(layer "In6.Cu")
		(net "M_C_CPU1_SA_DQS_DP<6>")
	)
	(segment
		(start 49.863248 -291.513768)
		(end 49.342548 -292.034214)
		(width 0.18288)
		(layer "In6.Cu")
		(net "M_C_CPU1_SA_DQS_DP<6>")
	)
	(segment
		(start 57.498488 -288.262568)
		(end 56.949848 -288.811208)
		(width 0.18288)
		(layer "In6.Cu")
		(net "M_C_CPU1_SA_DQS_DP<6>")
	)
	(segment
		(start 70.952106 -280.869898)
		(end 70.776084 -280.869898)
		(width 0.18288)
		(layer "In6.Cu")
		(net "M_C_CPU1_SA_DQS_DP<6>")
	)
	(segment
		(start 72.679814 -278.965406)
		(end 72.291702 -279.353772)
		(width 0.18288)
		(layer "In6.Cu")
		(net "M_C_CPU1_SA_DQS_DP<6>")
	)
	(segment
		(start 36.245038 -302.135032)
		(end 35.976814 -301.866808)
		(width 0.18288)
		(layer "In6.Cu")
		(net "M_C_CPU1_SA_DQS_DP<6>")
	)
	(segment
		(start 67.753484 -284.06979)
		(end 65.955926 -284.06979)
		(width 0.18288)
		(layer "In6.Cu")
		(net "M_C_CPU1_SA_DQS_DP<6>")
	)
	(segment
		(start 96.434148 -269.926562)
		(end 96.059244 -269.7099)
		(width 0.088646)
		(layer "In6.Cu")
		(net "M_C_CPU1_SA_DQS_DP<6>")
	)
	(segment
		(start 55.136796 -289.562794)
		(end 54.340252 -289.89274)
		(width 0.18288)
		(layer "In6.Cu")
		(net "M_C_CPU1_SA_DQS_DP<6>")
	)
	(segment
		(start 72.291956 -279.529794)
		(end 71.904098 -279.917652)
		(width 0.18288)
		(layer "In6.Cu")
		(net "M_C_CPU1_SA_DQS_DP<6>")
	)
	(segment
		(start 40.462962 -300.13148)
		(end 39.766748 -300.82744)
		(width 0.18288)
		(layer "In6.Cu")
		(net "M_C_CPU1_SA_DQS_DP<6>")
	)
	(segment
		(start 93.236796 -269.707868)
		(end 93.222064 -269.699232)
		(width 0.088646)
		(layer "In6.Cu")
		(net "M_C_CPU1_SA_DQS_DP<6>")
	)
	(segment
		(start 49.342548 -292.034214)
		(end 48.575976 -292.352222)
		(width 0.18288)
		(layer "In6.Cu")
		(net "M_C_CPU1_SA_DQS_DP<6>")
	)
	(segment
		(start 96.058482 -269.709392)
		(end 96.041464 -269.699486)
		(width 0.088646)
		(layer "In6.Cu")
		(net "M_C_CPU1_SA_DQS_DP<6>")
	)
	(segment
		(start 70.000114 -281.822144)
		(end 69.824092 -281.822144)
		(width 0.18288)
		(layer "In6.Cu")
		(net "M_C_CPU1_SA_DQS_DP<6>")
	)
	(segment
		(start 84.966048 -271.3863)
		(end 84.68614 -271.3863)
		(width 0.088646)
		(layer "In6.Cu")
		(net "M_C_CPU1_SA_DQS_DP<6>")
	)
	(segment
		(start 47.215552 -292.091872)
		(end 46.741334 -292.091872)
		(width 0.18288)
		(layer "In6.Cu")
		(net "M_C_CPU1_SA_DQS_DP<6>")
	)
	(segment
		(start 83.792568 -272.50644)
		(end 83.792568 -272.893536)
		(width 0.088646)
		(layer "In6.Cu")
		(net "M_C_CPU1_SA_DQS_DP<6>")
	)
	(segment
		(start 84.238846 -272.060162)
		(end 83.792568 -272.50644)
		(width 0.088646)
		(layer "In6.Cu")
		(net "M_C_CPU1_SA_DQS_DP<6>")
	)
	(segment
		(start 48.575976 -292.352222)
		(end 47.475902 -292.352222)
		(width 0.18288)
		(layer "In6.Cu")
		(net "M_C_CPU1_SA_DQS_DP<6>")
	)
	(segment
		(start 53.330856 -290.726368)
		(end 53.330856 -290.90239)
		(width 0.18288)
		(layer "In6.Cu")
		(net "M_C_CPU1_SA_DQS_DP<6>")
	)
	(segment
		(start 70.387972 -281.258264)
		(end 70.387972 -281.434286)
		(width 0.18288)
		(layer "In6.Cu")
		(net "M_C_CPU1_SA_DQS_DP<6>")
	)
	(segment
		(start 76.099416 -275.72081)
		(end 75.711812 -276.108668)
		(width 0.18288)
		(layer "In6.Cu")
		(net "M_C_CPU1_SA_DQS_DP<6>")
	)
	(segment
		(start 51.556158 -291.502084)
		(end 51.295808 -291.241734)
		(width 0.18288)
		(layer "In6.Cu")
		(net "M_C_CPU1_SA_DQS_DP<6>")
	)
	(segment
		(start 74.583798 -277.060914)
		(end 74.195686 -277.44928)
		(width 0.18288)
		(layer "In6.Cu")
		(net "M_C_CPU1_SA_DQS_DP<6>")
	)
	(segment
		(start 68.872354 -282.77439)
		(end 68.484242 -283.162756)
		(width 0.18288)
		(layer "In6.Cu")
		(net "M_C_CPU1_SA_DQS_DP<6>")
	)
	(segment
		(start 41.026588 -294.953182)
		(end 40.462962 -295.516808)
		(width 0.18288)
		(layer "In6.Cu")
		(net "M_C_CPU1_SA_DQS_DP<6>")
	)
	(segment
		(start 37.384736 -302.330104)
		(end 36.93668 -302.330104)
		(width 0.18288)
		(layer "In6.Cu")
		(net "M_C_CPU1_SA_DQS_DP<6>")
	)
	(segment
		(start 74.195686 -277.44928)
		(end 74.195686 -277.625302)
		(width 0.18288)
		(layer "In6.Cu")
		(net "M_C_CPU1_SA_DQS_DP<6>")
	)
	(segment
		(start 44.762928 -293.374064)
		(end 43.15587 -293.374064)
		(width 0.18288)
		(layer "In6.Cu")
		(net "M_C_CPU1_SA_DQS_DP<6>")
	)
	(segment
		(start 91.74226 -269.701772)
		(end 91.731846 -269.707868)
		(width 0.088646)
		(layer "In6.Cu")
		(net "M_C_CPU1_SA_DQS_DP<6>")
	)
	(segment
		(start 74.75982 -277.060914)
		(end 74.583798 -277.060914)
		(width 0.18288)
		(layer "In6.Cu")
		(net "M_C_CPU1_SA_DQS_DP<6>")
	)
	(segment
		(start 69.436234 -282.386532)
		(end 69.048376 -282.77439)
		(width 0.18288)
		(layer "In6.Cu")
		(net "M_C_CPU1_SA_DQS_DP<6>")
	)
	(segment
		(start 72.855836 -278.965406)
		(end 72.679814 -278.965406)
		(width 0.18288)
		(layer "In6.Cu")
		(net "M_C_CPU1_SA_DQS_DP<6>")
	)
	(segment
		(start 55.873904 -289.256978)
		(end 55.71109 -289.189668)
		(width 0.18288)
		(layer "In6.Cu")
		(net "M_C_CPU1_SA_DQS_DP<6>")
	)
	(segment
		(start 53.718968 -290.338256)
		(end 53.330856 -290.726368)
		(width 0.18288)
		(layer "In6.Cu")
		(net "M_C_CPU1_SA_DQS_DP<6>")
	)
	(segment
		(start 38.2651 -301.449486)
		(end 37.384736 -302.330104)
		(width 0.18288)
		(layer "In6.Cu")
		(net "M_C_CPU1_SA_DQS_DP<6>")
	)
	(segment
		(start 75.711812 -276.108668)
		(end 75.535536 -276.108668)
		(width 0.18288)
		(layer "In6.Cu")
		(net "M_C_CPU1_SA_DQS_DP<6>")
	)
	(segment
		(start 62.171072 -286.652208)
		(end 59.495436 -286.652208)
		(width 0.18288)
		(layer "In6.Cu")
		(net "M_C_CPU1_SA_DQS_DP<6>")
	)
	(segment
		(start 85.340444 -271.00149)
		(end 85.340444 -271.011396)
		(width 0.088646)
		(layer "In6.Cu")
		(net "M_C_CPU1_SA_DQS_DP<6>")
	)
	(segment
		(start 58.679334 -287.081722)
		(end 58.062876 -287.69818)
		(width 0.18288)
		(layer "In6.Cu")
		(net "M_C_CPU1_SA_DQS_DP<6>")
	)
	(segment
		(start 39.766748 -300.82744)
		(end 38.2651 -301.449486)
		(width 0.18288)
		(layer "In6.Cu")
		(net "M_C_CPU1_SA_DQS_DP<6>")
	)
	(segment
		(start 59.495436 -286.652208)
		(end 59.039506 -286.84093)
		(width 0.18288)
		(layer "In6.Cu")
		(net "M_C_CPU1_SA_DQS_DP<6>")
	)
	(segment
		(start 36.93668 -302.330104)
		(end 36.741608 -302.135032)
		(width 0.18288)
		(layer "In6.Cu")
		(net "M_C_CPU1_SA_DQS_DP<6>")
	)
	(segment
		(start 91.35745 -269.707868)
		(end 91.347036 -269.701772)
		(width 0.088646)
		(layer "In6.Cu")
		(net "M_C_CPU1_SA_DQS_DP<6>")
	)
	(segment
		(start 70.776084 -280.869898)
		(end 70.387972 -281.258264)
		(width 0.18288)
		(layer "In6.Cu")
		(net "M_C_CPU1_SA_DQS_DP<6>")
	)
	(segment
		(start 43.15587 -293.374064)
		(end 41.576752 -294.953182)
		(width 0.18288)
		(layer "In6.Cu")
		(net "M_C_CPU1_SA_DQS_DP<6>")
	)
	(segment
		(start 55.71109 -289.189668)
		(end 55.204106 -289.399726)
		(width 0.18288)
		(layer "In6.Cu")
		(net "M_C_CPU1_SA_DQS_DP<6>")
	)
	(segment
		(start 69.824092 -281.822144)
		(end 69.43598 -282.21051)
		(width 0.18288)
		(layer "In6.Cu")
		(net "M_C_CPU1_SA_DQS_DP<6>")
	)
	(segment
		(start 73.807828 -278.01316)
		(end 73.631806 -278.01316)
		(width 0.18288)
		(layer "In6.Cu")
		(net "M_C_CPU1_SA_DQS_DP<6>")
	)
	(segment
		(start 83.792568 -272.893536)
		(end 83.624166 -273.061938)
		(width 0.088646)
		(layer "In6.Cu")
		(net "M_C_CPU1_SA_DQS_DP<6>")
	)
	(segment
		(start 51.295808 -291.241734)
		(end 50.841402 -291.241734)
		(width 0.18288)
		(layer "In6.Cu")
		(net "M_C_CPU1_SA_DQS_DP<6>")
	)
	(segment
		(start 55.204106 -289.399726)
		(end 55.136796 -289.562794)
		(width 0.18288)
		(layer "In6.Cu")
		(net "M_C_CPU1_SA_DQS_DP<6>")
	)
	(segment
		(start 65.315592 -284.710124)
		(end 65.13957 -284.710124)
		(width 0.18288)
		(layer "In6.Cu")
		(net "M_C_CPU1_SA_DQS_DP<6>")
	)
	(segment
		(start 83.342988 -273.002248)
		(end 82.66303 -273.002248)
		(width 0.18288)
		(layer "In6.Cu")
		(net "M_C_CPU1_SA_DQS_DP<6>")
	)
	(segment
		(start 64.751458 -285.274258)
		(end 64.3636 -285.662116)
		(width 0.18288)
		(layer "In6.Cu")
		(net "M_C_CPU1_SA_DQS_DP<6>")
	)
	(segment
		(start 86.571582 -270.516858)
		(end 86.562692 -270.521938)
		(width 0.088646)
		(layer "In6.Cu")
		(net "M_C_CPU1_SA_DQS_DP<6>")
	)
	(segment
		(start 74.195686 -277.625302)
		(end 73.807828 -278.01316)
		(width 0.18288)
		(layer "In6.Cu")
		(net "M_C_CPU1_SA_DQS_DP<6>")
	)
	(segment
		(start 50.569368 -291.513768)
		(end 49.863248 -291.513768)
		(width 0.18288)
		(layer "In6.Cu")
		(net "M_C_CPU1_SA_DQS_DP<6>")
	)
	(segment
		(start 70.387972 -281.434286)
		(end 70.000114 -281.822144)
		(width 0.18288)
		(layer "In6.Cu")
		(net "M_C_CPU1_SA_DQS_DP<6>")
	)
	(segment
		(start 54.340252 -289.89274)
		(end 53.89499 -290.338002)
		(width 0.18288)
		(layer "In6.Cu")
		(net "M_C_CPU1_SA_DQS_DP<6>")
	)
	(segment
		(start 64.3636 -285.662116)
		(end 63.161164 -285.662116)
		(width 0.18288)
		(layer "In6.Cu")
		(net "M_C_CPU1_SA_DQS_DP<6>")
	)
	(segment
		(start 84.238846 -271.833594)
		(end 84.238846 -272.060162)
		(width 0.088646)
		(layer "In6.Cu")
		(net "M_C_CPU1_SA_DQS_DP<6>")
	)
	(segment
		(start 95.116396 -269.707868)
		(end 95.101664 -269.699232)
		(width 0.088646)
		(layer "In6.Cu")
		(net "M_C_CPU1_SA_DQS_DP<6>")
	)
	(segment
		(start 96.059244 -269.7099)
		(end 96.058482 -269.709392)
		(width 0.088646)
		(layer "In6.Cu")
		(net "M_C_CPU1_SA_DQS_DP<6>")
	)
	(segment
		(start 73.243694 -278.577548)
		(end 72.855836 -278.965406)
		(width 0.18288)
		(layer "In6.Cu")
		(net "M_C_CPU1_SA_DQS_DP<6>")
	)
	(segment
		(start 86.750144 -270.179038)
		(end 86.750144 -270.19758)
		(width 0.088646)
		(layer "In6.Cu")
		(net "M_C_CPU1_SA_DQS_DP<6>")
	)
	(segment
		(start 63.161164 -285.662116)
		(end 62.171072 -286.652208)
		(width 0.18288)
		(layer "In6.Cu")
		(net "M_C_CPU1_SA_DQS_DP<6>")
	)
	(segment
		(start 65.955926 -284.06979)
		(end 65.315592 -284.710124)
		(width 0.18288)
		(layer "In6.Cu")
		(net "M_C_CPU1_SA_DQS_DP<6>")
	)
	(segment
		(start 72.291702 -279.353772)
		(end 72.291956 -279.529794)
		(width 0.18288)
		(layer "In6.Cu")
		(net "M_C_CPU1_SA_DQS_DP<6>")
	)
	(segment
		(start 68.484242 -283.338778)
		(end 67.753484 -284.06979)
		(width 0.18288)
		(layer "In6.Cu")
		(net "M_C_CPU1_SA_DQS_DP<6>")
	)
	(segment
		(start 59.039506 -286.84093)
		(end 58.679334 -287.081722)
		(width 0.18288)
		(layer "In6.Cu")
		(net "M_C_CPU1_SA_DQS_DP<6>")
	)
	(segment
		(start 73.243694 -278.401526)
		(end 73.243694 -278.577548)
		(width 0.18288)
		(layer "In6.Cu")
		(net "M_C_CPU1_SA_DQS_DP<6>")
	)
	(segment
		(start 64.751458 -285.098236)
		(end 64.751458 -285.274258)
		(width 0.18288)
		(layer "In6.Cu")
		(net "M_C_CPU1_SA_DQS_DP<6>")
	)
	(segment
		(start 53.89499 -290.338002)
		(end 53.718968 -290.338256)
		(width 0.18288)
		(layer "In6.Cu")
		(net "M_C_CPU1_SA_DQS_DP<6>")
	)
	(segment
		(start 36.741608 -302.135032)
		(end 36.245038 -302.135032)
		(width 0.18288)
		(layer "In6.Cu")
		(net "M_C_CPU1_SA_DQS_DP<6>")
	)
	(segment
		(start 57.886854 -287.69818)
		(end 57.498488 -288.086546)
		(width 0.18288)
		(layer "In6.Cu")
		(net "M_C_CPU1_SA_DQS_DP<6>")
	)
	(segment
		(start 83.624166 -273.061938)
		(end 83.426046 -273.061938)
		(width 0.088646)
		(layer "In6.Cu")
		(net "M_C_CPU1_SA_DQS_DP<6>")
	)
	(segment
		(start 68.484242 -283.162756)
		(end 68.484242 -283.338778)
		(width 0.18288)
		(layer "In6.Cu")
		(net "M_C_CPU1_SA_DQS_DP<6>")
	)
	(segment
		(start 94.176596 -269.707868)
		(end 94.161864 -269.699232)
		(width 0.088646)
		(layer "In6.Cu")
		(net "M_C_CPU1_SA_DQS_DP<6>")
	)
	(segment
		(start 58.062876 -287.69818)
		(end 57.886854 -287.69818)
		(width 0.18288)
		(layer "In6.Cu")
		(net "M_C_CPU1_SA_DQS_DP<6>")
	)
	(segment
		(start 52.731162 -291.502084)
		(end 51.556158 -291.502084)
		(width 0.18288)
		(layer "In6.Cu")
		(net "M_C_CPU1_SA_DQS_DP<6>")
	)
	(segment
		(start 46.741334 -292.091872)
		(end 46.49216 -292.341046)
		(width 0.18288)
		(layer "In6.Cu")
		(net "M_C_CPU1_SA_DQS_DP<6>")
	)
	(segment
		(start 47.475902 -292.352222)
		(end 47.215552 -292.091872)
		(width 0.18288)
		(layer "In6.Cu")
		(net "M_C_CPU1_SA_DQS_DP<6>")
	)
	(segment
		(start 40.462962 -295.516808)
		(end 40.462962 -300.13148)
		(width 0.18288)
		(layer "In6.Cu")
		(net "M_C_CPU1_SA_DQS_DP<6>")
	)
	(segment
		(start 75.147678 -276.673056)
		(end 74.75982 -277.060914)
		(width 0.18288)
		(layer "In6.Cu")
		(net "M_C_CPU1_SA_DQS_DP<6>")
	)
	(segment
		(start 53.330856 -290.90239)
		(end 52.731162 -291.502084)
		(width 0.18288)
		(layer "In6.Cu")
		(net "M_C_CPU1_SA_DQS_DP<6>")
	)
	(segment
		(start 69.048376 -282.77439)
		(end 68.872354 -282.77439)
		(width 0.18288)
		(layer "In6.Cu")
		(net "M_C_CPU1_SA_DQS_DP<6>")
	)
	(segment
		(start 57.498488 -288.086546)
		(end 57.498488 -288.262568)
		(width 0.18288)
		(layer "In6.Cu")
		(net "M_C_CPU1_SA_DQS_DP<6>")
	)
	(segment
		(start 71.339964 -280.48204)
		(end 70.952106 -280.869898)
		(width 0.18288)
		(layer "In6.Cu")
		(net "M_C_CPU1_SA_DQS_DP<6>")
	)
	(segment
		(start 83.366356 -273.002248)
		(end 83.342988 -273.002248)
		(width 0.088646)
		(layer "In6.Cu")
		(net "M_C_CPU1_SA_DQS_DP<6>")
	)
	(segment
		(start 71.904098 -279.917652)
		(end 71.728076 -279.917652)
		(width 0.18288)
		(layer "In6.Cu")
		(net "M_C_CPU1_SA_DQS_DP<6>")
	)
	(segment
		(start 71.339964 -280.306018)
		(end 71.339964 -280.48204)
		(width 0.18288)
		(layer "In6.Cu")
		(net "M_C_CPU1_SA_DQS_DP<6>")
	)
	(segment
		(start 45.795946 -292.341046)
		(end 44.762928 -293.374064)
		(width 0.18288)
		(layer "In6.Cu")
		(net "M_C_CPU1_SA_DQS_DP<6>")
	)
	(segment
		(start 41.576752 -294.953182)
		(end 41.026588 -294.953182)
		(width 0.18288)
		(layer "In6.Cu")
		(net "M_C_CPU1_SA_DQS_DP<6>")
	)
	(segment
		(start 75.147424 -276.497034)
		(end 75.147678 -276.673056)
		(width 0.18288)
		(layer "In6.Cu")
		(net "M_C_CPU1_SA_DQS_DP<6>")
	)
	(segment
		(start 69.43598 -282.21051)
		(end 69.436234 -282.386532)
		(width 0.18288)
		(layer "In6.Cu")
		(net "M_C_CPU1_SA_DQS_DP<6>")
	)
	(segment
		(start 46.49216 -292.341046)
		(end 45.795946 -292.341046)
		(width 0.18288)
		(layer "In6.Cu")
		(net "M_C_CPU1_SA_DQS_DP<6>")
	)
	(segment
		(start 82.66303 -273.002248)
		(end 76.099416 -275.72081)
		(width 0.18288)
		(layer "In6.Cu")
		(net "M_C_CPU1_SA_DQS_DP<6>")
	)
	(segment
		(start 83.426046 -273.061938)
		(end 83.366356 -273.002248)
		(width 0.088646)
		(layer "In6.Cu")
		(net "M_C_CPU1_SA_DQS_DP<6>")
	)
	(segment
		(start 50.841402 -291.241734)
		(end 50.569368 -291.513768)
		(width 0.18288)
		(layer "In6.Cu")
		(net "M_C_CPU1_SA_DQS_DP<6>")
	)
	(segment
		(start 96.713548 -270.19758)
		(end 96.434148 -269.926562)
		(width 0.088646)
		(layer "In6.Cu")
		(net "M_C_CPU1_SA_DQS_DP<6>")
	)
	(segment
		(start 84.68614 -271.3863)
		(end 84.238846 -271.833594)
		(width 0.088646)
		(layer "In6.Cu")
		(net "M_C_CPU1_SA_DQS_DP<6>")
	)
	(arc
		(start 91.731846 -269.707868)
		(mid 91.544648 -269.758011)
		(end 91.35745 -269.707868)
		(width 0.088646)
		(layer "In6.Cu")
		(net "M_C_CPU1_SA_DQS_DP<6>")
	)
	(arc
		(start 96.041464 -269.699486)
		(mid 95.764989 -269.632166)
		(end 95.490792 -269.708122)
		(width 0.088646)
		(layer "In6.Cu")
		(net "M_C_CPU1_SA_DQS_DP<6>")
	)
	(arc
		(start 89.851992 -269.707868)
		(mid 89.664794 -269.758011)
		(end 89.477596 -269.707868)
		(width 0.088646)
		(layer "In6.Cu")
		(net "M_C_CPU1_SA_DQS_DP<6>")
	)
	(arc
		(start 95.101664 -269.699232)
		(mid 94.825223 -269.632066)
		(end 94.550992 -269.707868)
		(width 0.088646)
		(layer "In6.Cu")
		(net "M_C_CPU1_SA_DQS_DP<6>")
	)
	(arc
		(start 86.562692 -270.521938)
		(mid 86.375494 -270.572081)
		(end 86.188296 -270.521938)
		(width 0.088646)
		(layer "In6.Cu")
		(net "M_C_CPU1_SA_DQS_DP<6>")
	)
	(arc
		(start 95.490792 -269.707868)
		(mid 95.303594 -269.758011)
		(end 95.116396 -269.707868)
		(width 0.088646)
		(layer "In6.Cu")
		(net "M_C_CPU1_SA_DQS_DP<6>")
	)
	(arc
		(start 93.222064 -269.699232)
		(mid 92.945623 -269.632066)
		(end 92.671392 -269.707868)
		(width 0.088646)
		(layer "In6.Cu")
		(net "M_C_CPU1_SA_DQS_DP<6>")
	)
	(arc
		(start 85.340444 -271.011396)
		(mid 85.230817 -271.276313)
		(end 84.966048 -271.3863)
		(width 0.088646)
		(layer "In6.Cu")
		(net "M_C_CPU1_SA_DQS_DP<6>")
	)
	(arc
		(start 88.912192 -269.707868)
		(mid 88.724994 -269.758011)
		(end 88.537796 -269.707868)
		(width 0.088646)
		(layer "In6.Cu")
		(net "M_C_CPU1_SA_DQS_DP<6>")
	)
	(arc
		(start 92.671392 -269.707868)
		(mid 92.484194 -269.758011)
		(end 92.296996 -269.707868)
		(width 0.088646)
		(layer "In6.Cu")
		(net "M_C_CPU1_SA_DQS_DP<6>")
	)
	(arc
		(start 94.550992 -269.707868)
		(mid 94.363794 -269.758011)
		(end 94.176596 -269.707868)
		(width 0.088646)
		(layer "In6.Cu")
		(net "M_C_CPU1_SA_DQS_DP<6>")
	)
	(arc
		(start 94.161864 -269.699232)
		(mid 93.885423 -269.632066)
		(end 93.611192 -269.707868)
		(width 0.088646)
		(layer "In6.Cu")
		(net "M_C_CPU1_SA_DQS_DP<6>")
	)
	(arc
		(start 92.296996 -269.707868)
		(mid 92.020437 -269.632159)
		(end 91.74226 -269.701772)
		(width 0.088646)
		(layer "In6.Cu")
		(net "M_C_CPU1_SA_DQS_DP<6>")
	)
	(arc
		(start 87.597996 -269.707868)
		(mid 87.315294 -269.632126)
		(end 87.032592 -269.707868)
		(width 0.088646)
		(layer "In6.Cu")
		(net "M_C_CPU1_SA_DQS_DP<6>")
	)
	(arc
		(start 88.537796 -269.707868)
		(mid 88.255094 -269.632126)
		(end 87.972392 -269.707868)
		(width 0.088646)
		(layer "In6.Cu")
		(net "M_C_CPU1_SA_DQS_DP<6>")
	)
	(arc
		(start 93.611192 -269.707868)
		(mid 93.423994 -269.758011)
		(end 93.236796 -269.707868)
		(width 0.088646)
		(layer "In6.Cu")
		(net "M_C_CPU1_SA_DQS_DP<6>")
	)
	(arc
		(start 90.791792 -269.707868)
		(mid 90.604594 -269.758011)
		(end 90.417396 -269.707868)
		(width 0.088646)
		(layer "In6.Cu")
		(net "M_C_CPU1_SA_DQS_DP<6>")
	)
	(arc
		(start 85.622892 -270.521938)
		(mid 85.418557 -270.724543)
		(end 85.340444 -271.00149)
		(width 0.088646)
		(layer "In6.Cu")
		(net "M_C_CPU1_SA_DQS_DP<6>")
	)
	(arc
		(start 86.188296 -270.521938)
		(mid 85.905594 -270.446162)
		(end 85.622892 -270.521938)
		(width 0.088646)
		(layer "In6.Cu")
		(net "M_C_CPU1_SA_DQS_DP<6>")
	)
	(arc
		(start 89.477596 -269.707868)
		(mid 89.194894 -269.632126)
		(end 88.912192 -269.707868)
		(width 0.088646)
		(layer "In6.Cu")
		(net "M_C_CPU1_SA_DQS_DP<6>")
	)
	(arc
		(start 87.032592 -269.707868)
		(mid 86.830306 -269.906849)
		(end 86.750144 -270.179038)
		(width 0.088646)
		(layer "In6.Cu")
		(net "M_C_CPU1_SA_DQS_DP<6>")
	)
	(arc
		(start 86.750144 -270.19758)
		(mid 86.702465 -270.38048)
		(end 86.571582 -270.516858)
		(width 0.088646)
		(layer "In6.Cu")
		(net "M_C_CPU1_SA_DQS_DP<6>")
	)
	(arc
		(start 91.347036 -269.701772)
		(mid 91.068604 -269.631958)
		(end 90.791792 -269.707868)
		(width 0.088646)
		(layer "In6.Cu")
		(net "M_C_CPU1_SA_DQS_DP<6>")
	)
	(arc
		(start 90.417396 -269.707868)
		(mid 90.134694 -269.632126)
		(end 89.851992 -269.707868)
		(width 0.088646)
		(layer "In6.Cu")
		(net "M_C_CPU1_SA_DQS_DP<6>")
	)
	(arc
		(start 87.972392 -269.707868)
		(mid 87.785194 -269.758011)
		(end 87.597996 -269.707868)
		(width 0.088646)
		(layer "In6.Cu")
		(net "M_C_CPU1_SA_DQS_DP<6>")
	)
	(segment
		(start 33.516316 -311.477914)
		(end 34.120836 -311.477914)
		(width 0.20066)
		(layer "F.Cu")
		(net "M_C_CPU1_SA_DQS_DP<5>")
	)
	(segment
		(start 29.450284 -310.786018)
		(end 29.647642 -310.786018)
		(width 0.20066)
		(layer "F.Cu")
		(net "M_C_CPU1_SA_DQS_DP<5>")
	)
	(segment
		(start 94.363794 -276.986746)
		(end 94.363794 -277.522432)
		(width 0.20066)
		(layer "F.Cu")
		(net "M_C_CPU1_SA_DQS_DP<5>")
	)
	(segment
		(start 31.972758 -310.79186)
		(end 32.114236 -310.79186)
		(width 0.20066)
		(layer "F.Cu")
		(net "M_C_CPU1_SA_DQS_DP<5>")
	)
	(segment
		(start 28.398216 -311.477914)
		(end 28.820618 -311.055512)
		(width 0.20066)
		(layer "F.Cu")
		(net "M_C_CPU1_SA_DQS_DP<5>")
	)
	(segment
		(start 28.063952 -311.477914)
		(end 28.398216 -311.477914)
		(width 0.20066)
		(layer "F.Cu")
		(net "M_C_CPU1_SA_DQS_DP<5>")
	)
	(segment
		(start 29.894276 -310.79186)
		(end 31.972758 -310.79186)
		(width 0.1016)
		(layer "F.Cu")
		(net "M_C_CPU1_SA_DQS_DP<5>")
	)
	(segment
		(start 29.18079 -311.055512)
		(end 29.450284 -310.786018)
		(width 0.20066)
		(layer "F.Cu")
		(net "M_C_CPU1_SA_DQS_DP<5>")
	)
	(segment
		(start 27.328114 -311.216802)
		(end 27.80284 -311.216802)
		(width 0.20066)
		(layer "F.Cu")
		(net "M_C_CPU1_SA_DQS_DP<5>")
	)
	(segment
		(start 32.114236 -310.79186)
		(end 32.375348 -311.052972)
		(width 0.20066)
		(layer "F.Cu")
		(net "M_C_CPU1_SA_DQS_DP<5>")
	)
	(segment
		(start 34.120836 -311.477914)
		(end 34.381948 -311.216802)
		(width 0.20066)
		(layer "F.Cu")
		(net "M_C_CPU1_SA_DQS_DP<5>")
	)
	(segment
		(start 29.653484 -310.79186)
		(end 29.894276 -310.79186)
		(width 0.101854)
		(layer "F.Cu")
		(net "M_C_CPU1_SA_DQS_DP<5>")
	)
	(segment
		(start 35.976814 -311.216802)
		(end 34.871914 -311.216802)
		(width 0.20066)
		(layer "F.Cu")
		(net "M_C_CPU1_SA_DQS_DP<5>")
	)
	(segment
		(start 32.8803 -311.052972)
		(end 33.516316 -311.477914)
		(width 0.20066)
		(layer "F.Cu")
		(net "M_C_CPU1_SA_DQS_DP<5>")
	)
	(segment
		(start 34.381948 -311.216802)
		(end 34.871914 -311.216802)
		(width 0.20066)
		(layer "F.Cu")
		(net "M_C_CPU1_SA_DQS_DP<5>")
	)
	(segment
		(start 28.820618 -311.055512)
		(end 29.18079 -311.055512)
		(width 0.20066)
		(layer "F.Cu")
		(net "M_C_CPU1_SA_DQS_DP<5>")
	)
	(segment
		(start 94.364048 -276.986492)
		(end 94.363794 -276.986746)
		(width 0.20066)
		(layer "F.Cu")
		(net "M_C_CPU1_SA_DQS_DP<5>")
	)
	(segment
		(start 29.647642 -310.786018)
		(end 29.653484 -310.79186)
		(width 0.101854)
		(layer "F.Cu")
		(net "M_C_CPU1_SA_DQS_DP<5>")
	)
	(segment
		(start 32.375348 -311.052972)
		(end 32.8803 -311.052972)
		(width 0.20066)
		(layer "F.Cu")
		(net "M_C_CPU1_SA_DQS_DP<5>")
	)
	(segment
		(start 27.80284 -311.216802)
		(end 28.063952 -311.477914)
		(width 0.20066)
		(layer "F.Cu")
		(net "M_C_CPU1_SA_DQS_DP<5>")
	)
	(segment
		(start 49.789842 -312.746136)
		(end 48.916844 -313.619134)
		(width 0.18288)
		(layer "In4.Cu")
		(net "M_C_CPU1_SA_DQS_DP<5>")
	)
	(segment
		(start 44.070524 -312.102246)
		(end 41.57853 -312.102246)
		(width 0.18288)
		(layer "In4.Cu")
		(net "M_C_CPU1_SA_DQS_DP<5>")
	)
	(segment
		(start 88.912954 -279.474168)
		(end 88.912192 -279.474676)
		(width 0.088646)
		(layer "In4.Cu")
		(net "M_C_CPU1_SA_DQS_DP<5>")
	)
	(segment
		(start 85.340444 -283.760418)
		(end 84.881974 -284.218888)
		(width 0.088646)
		(layer "In4.Cu")
		(net "M_C_CPU1_SA_DQS_DP<5>")
	)
	(segment
		(start 51.502056 -312.75782)
		(end 51.235864 -312.491628)
		(width 0.18288)
		(layer "In4.Cu")
		(net "M_C_CPU1_SA_DQS_DP<5>")
	)
	(segment
		(start 87.51316 -281.910282)
		(end 87.49665 -281.919934)
		(width 0.088646)
		(layer "In4.Cu")
		(net "M_C_CPU1_SA_DQS_DP<5>")
	)
	(segment
		(start 88.912192 -280.453846)
		(end 88.921082 -280.458926)
		(width 0.088646)
		(layer "In4.Cu")
		(net "M_C_CPU1_SA_DQS_DP<5>")
	)
	(segment
		(start 45.180504 -312.760614)
		(end 44.728892 -312.760614)
		(width 0.18288)
		(layer "In4.Cu")
		(net "M_C_CPU1_SA_DQS_DP<5>")
	)
	(segment
		(start 36.244276 -311.484264)
		(end 35.976814 -311.216802)
		(width 0.18288)
		(layer "In4.Cu")
		(net "M_C_CPU1_SA_DQS_DP<5>")
	)
	(segment
		(start 89.390982 -278.65578)
		(end 89.382092 -278.66086)
		(width 0.088646)
		(layer "In4.Cu")
		(net "M_C_CPU1_SA_DQS_DP<5>")
	)
	(segment
		(start 55.051452 -312.75782)
		(end 51.502056 -312.75782)
		(width 0.18288)
		(layer "In4.Cu")
		(net "M_C_CPU1_SA_DQS_DP<5>")
	)
	(segment
		(start 62.874398 -310.484266)
		(end 59.251342 -310.484266)
		(width 0.18288)
		(layer "In4.Cu")
		(net "M_C_CPU1_SA_DQS_DP<5>")
	)
	(segment
		(start 41.29405 -311.817766)
		(end 36.970462 -311.817766)
		(width 0.18288)
		(layer "In4.Cu")
		(net "M_C_CPU1_SA_DQS_DP<5>")
	)
	(segment
		(start 90.887296 -277.032974)
		(end 90.872564 -277.024338)
		(width 0.088646)
		(layer "In4.Cu")
		(net "M_C_CPU1_SA_DQS_DP<5>")
	)
	(segment
		(start 89.099644 -279.140412)
		(end 89.099644 -279.150318)
		(width 0.088646)
		(layer "In4.Cu")
		(net "M_C_CPU1_SA_DQS_DP<5>")
	)
	(segment
		(start 57.490868 -311.421018)
		(end 56.388254 -311.421018)
		(width 0.18288)
		(layer "In4.Cu")
		(net "M_C_CPU1_SA_DQS_DP<5>")
	)
	(segment
		(start 92.216478 -277.024338)
		(end 92.201746 -277.032974)
		(width 0.088646)
		(layer "In4.Cu")
		(net "M_C_CPU1_SA_DQS_DP<5>")
	)
	(segment
		(start 84.493354 -284.702504)
		(end 81.4832 -287.712658)
		(width 0.18288)
		(layer "In4.Cu")
		(net "M_C_CPU1_SA_DQS_DP<5>")
	)
	(segment
		(start 88.907366 -281.105356)
		(end 88.906096 -281.106118)
		(width 0.088646)
		(layer "In4.Cu")
		(net "M_C_CPU1_SA_DQS_DP<5>")
	)
	(segment
		(start 84.881974 -284.218888)
		(end 84.755228 -284.524704)
		(width 0.088646)
		(layer "In4.Cu")
		(net "M_C_CPU1_SA_DQS_DP<5>")
	)
	(segment
		(start 85.810344 -283.201364)
		(end 85.810344 -283.219906)
		(width 0.088646)
		(layer "In4.Cu")
		(net "M_C_CPU1_SA_DQS_DP<5>")
	)
	(segment
		(start 85.810344 -283.226256)
		(end 85.810598 -283.22651)
		(width 0.088646)
		(layer "In4.Cu")
		(net "M_C_CPU1_SA_DQS_DP<5>")
	)
	(segment
		(start 36.970462 -311.817766)
		(end 36.63696 -311.484264)
		(width 0.18288)
		(layer "In4.Cu")
		(net "M_C_CPU1_SA_DQS_DP<5>")
	)
	(segment
		(start 84.755228 -284.524704)
		(end 84.598764 -284.681168)
		(width 0.088646)
		(layer "In4.Cu")
		(net "M_C_CPU1_SA_DQS_DP<5>")
	)
	(segment
		(start 46.770544 -313.341766)
		(end 46.513242 -313.599068)
		(width 0.18288)
		(layer "In4.Cu")
		(net "M_C_CPU1_SA_DQS_DP<5>")
	)
	(segment
		(start 64.598042 -310.893206)
		(end 63.283338 -310.893206)
		(width 0.18288)
		(layer "In4.Cu")
		(net "M_C_CPU1_SA_DQS_DP<5>")
	)
	(segment
		(start 51.235864 -312.491628)
		(end 50.872136 -312.491628)
		(width 0.18288)
		(layer "In4.Cu")
		(net "M_C_CPU1_SA_DQS_DP<5>")
	)
	(segment
		(start 81.4832 -287.712658)
		(end 77.838808 -296.509186)
		(width 0.18288)
		(layer "In4.Cu")
		(net "M_C_CPU1_SA_DQS_DP<5>")
	)
	(segment
		(start 44.728892 -312.760614)
		(end 44.070524 -312.102246)
		(width 0.18288)
		(layer "In4.Cu")
		(net "M_C_CPU1_SA_DQS_DP<5>")
	)
	(segment
		(start 87.220044 -282.405836)
		(end 87.220044 -282.414472)
		(width 0.088646)
		(layer "In4.Cu")
		(net "M_C_CPU1_SA_DQS_DP<5>")
	)
	(segment
		(start 93.156278 -277.024338)
		(end 93.141546 -277.032974)
		(width 0.088646)
		(layer "In4.Cu")
		(net "M_C_CPU1_SA_DQS_DP<5>")
	)
	(segment
		(start 88.921082 -281.097482)
		(end 88.907366 -281.105356)
		(width 0.088646)
		(layer "In4.Cu")
		(net "M_C_CPU1_SA_DQS_DP<5>")
	)
	(segment
		(start 41.57853 -312.102246)
		(end 41.29405 -311.817766)
		(width 0.18288)
		(layer "In4.Cu")
		(net "M_C_CPU1_SA_DQS_DP<5>")
	)
	(segment
		(start 47.135796 -313.341766)
		(end 46.770544 -313.341766)
		(width 0.18288)
		(layer "In4.Cu")
		(net "M_C_CPU1_SA_DQS_DP<5>")
	)
	(segment
		(start 94.05112 -277.522432)
		(end 93.985588 -277.4569)
		(width 0.088646)
		(layer "In4.Cu")
		(net "M_C_CPU1_SA_DQS_DP<5>")
	)
	(segment
		(start 70.583298 -304.90795)
		(end 64.598042 -310.893206)
		(width 0.18288)
		(layer "In4.Cu")
		(net "M_C_CPU1_SA_DQS_DP<5>")
	)
	(segment
		(start 77.838808 -296.509186)
		(end 70.583298 -303.764696)
		(width 0.18288)
		(layer "In4.Cu")
		(net "M_C_CPU1_SA_DQS_DP<5>")
	)
	(segment
		(start 94.363794 -277.522432)
		(end 94.05112 -277.522432)
		(width 0.088646)
		(layer "In4.Cu")
		(net "M_C_CPU1_SA_DQS_DP<5>")
	)
	(segment
		(start 46.513242 -313.599068)
		(end 46.018958 -313.599068)
		(width 0.18288)
		(layer "In4.Cu")
		(net "M_C_CPU1_SA_DQS_DP<5>")
	)
	(segment
		(start 88.921082 -279.469596)
		(end 88.912954 -279.474168)
		(width 0.088646)
		(layer "In4.Cu")
		(net "M_C_CPU1_SA_DQS_DP<5>")
	)
	(segment
		(start 50.872136 -312.491628)
		(end 50.617628 -312.746136)
		(width 0.18288)
		(layer "In4.Cu")
		(net "M_C_CPU1_SA_DQS_DP<5>")
	)
	(segment
		(start 46.018958 -313.599068)
		(end 45.180504 -312.760614)
		(width 0.18288)
		(layer "In4.Cu")
		(net "M_C_CPU1_SA_DQS_DP<5>")
	)
	(segment
		(start 84.598764 -284.681168)
		(end 84.51469 -284.681168)
		(width 0.088646)
		(layer "In4.Cu")
		(net "M_C_CPU1_SA_DQS_DP<5>")
	)
	(segment
		(start 89.569544 -278.31796)
		(end 89.569544 -278.336502)
		(width 0.088646)
		(layer "In4.Cu")
		(net "M_C_CPU1_SA_DQS_DP<5>")
	)
	(segment
		(start 70.583298 -303.764696)
		(end 70.583298 -304.90795)
		(width 0.18288)
		(layer "In4.Cu")
		(net "M_C_CPU1_SA_DQS_DP<5>")
	)
	(segment
		(start 89.860882 -277.84171)
		(end 89.851992 -277.84679)
		(width 0.088646)
		(layer "In4.Cu")
		(net "M_C_CPU1_SA_DQS_DP<5>")
	)
	(segment
		(start 84.51469 -284.681168)
		(end 84.493354 -284.702504)
		(width 0.088646)
		(layer "In4.Cu")
		(net "M_C_CPU1_SA_DQS_DP<5>")
	)
	(segment
		(start 48.916844 -313.619134)
		(end 47.413164 -313.619134)
		(width 0.18288)
		(layer "In4.Cu")
		(net "M_C_CPU1_SA_DQS_DP<5>")
	)
	(segment
		(start 47.413164 -313.619134)
		(end 47.135796 -313.341766)
		(width 0.18288)
		(layer "In4.Cu")
		(net "M_C_CPU1_SA_DQS_DP<5>")
	)
	(segment
		(start 91.272106 -277.026878)
		(end 91.261692 -277.032974)
		(width 0.088646)
		(layer "In4.Cu")
		(net "M_C_CPU1_SA_DQS_DP<5>")
	)
	(segment
		(start 63.283338 -310.893206)
		(end 62.874398 -310.484266)
		(width 0.18288)
		(layer "In4.Cu")
		(net "M_C_CPU1_SA_DQS_DP<5>")
	)
	(segment
		(start 36.63696 -311.484264)
		(end 36.244276 -311.484264)
		(width 0.18288)
		(layer "In4.Cu")
		(net "M_C_CPU1_SA_DQS_DP<5>")
	)
	(segment
		(start 56.388254 -311.421018)
		(end 55.051452 -312.75782)
		(width 0.18288)
		(layer "In4.Cu")
		(net "M_C_CPU1_SA_DQS_DP<5>")
	)
	(segment
		(start 50.617628 -312.746136)
		(end 49.789842 -312.746136)
		(width 0.18288)
		(layer "In4.Cu")
		(net "M_C_CPU1_SA_DQS_DP<5>")
	)
	(segment
		(start 58.895996 -310.839104)
		(end 57.490868 -311.421018)
		(width 0.18288)
		(layer "In4.Cu")
		(net "M_C_CPU1_SA_DQS_DP<5>")
	)
	(segment
		(start 59.251342 -310.484266)
		(end 58.895996 -310.839104)
		(width 0.18288)
		(layer "In4.Cu")
		(net "M_C_CPU1_SA_DQS_DP<5>")
	)
	(arc
		(start 93.141546 -277.032974)
		(mid 92.954348 -277.083117)
		(end 92.76715 -277.032974)
		(width 0.088646)
		(layer "In4.Cu")
		(net "M_C_CPU1_SA_DQS_DP<5>")
	)
	(arc
		(start 86.65845 -282.730194)
		(mid 86.100857 -282.725481)
		(end 85.810344 -283.201364)
		(width 0.088646)
		(layer "In4.Cu")
		(net "M_C_CPU1_SA_DQS_DP<5>")
	)
	(arc
		(start 91.82735 -277.032974)
		(mid 91.550537 -276.957104)
		(end 91.272106 -277.026878)
		(width 0.088646)
		(layer "In4.Cu")
		(net "M_C_CPU1_SA_DQS_DP<5>")
	)
	(arc
		(start 93.985588 -277.4569)
		(mid 93.98429 -277.446346)
		(end 93.982794 -277.435818)
		(width 0.088646)
		(layer "In4.Cu")
		(net "M_C_CPU1_SA_DQS_DP<5>")
	)
	(arc
		(start 93.70695 -277.032974)
		(mid 93.432751 -276.957139)
		(end 93.156278 -277.024338)
		(width 0.088646)
		(layer "In4.Cu")
		(net "M_C_CPU1_SA_DQS_DP<5>")
	)
	(arc
		(start 90.315796 -277.03653)
		(mid 90.113383 -277.242943)
		(end 90.039444 -277.522432)
		(width 0.088646)
		(layer "In4.Cu")
		(net "M_C_CPU1_SA_DQS_DP<5>")
	)
	(arc
		(start 85.810344 -283.219906)
		(mid 85.810359 -283.223081)
		(end 85.810344 -283.226256)
		(width 0.088646)
		(layer "In4.Cu")
		(net "M_C_CPU1_SA_DQS_DP<5>")
	)
	(arc
		(start 89.09939 -280.788364)
		(mid 89.049375 -280.965495)
		(end 88.921082 -281.097482)
		(width 0.088646)
		(layer "In4.Cu")
		(net "M_C_CPU1_SA_DQS_DP<5>")
	)
	(arc
		(start 89.382092 -278.66086)
		(mid 89.177757 -278.863465)
		(end 89.099644 -279.140412)
		(width 0.088646)
		(layer "In4.Cu")
		(net "M_C_CPU1_SA_DQS_DP<5>")
	)
	(arc
		(start 90.039444 -277.522432)
		(mid 89.991765 -277.705332)
		(end 89.860882 -277.84171)
		(width 0.088646)
		(layer "In4.Cu")
		(net "M_C_CPU1_SA_DQS_DP<5>")
	)
	(arc
		(start 91.261692 -277.032974)
		(mid 91.074494 -277.083117)
		(end 90.887296 -277.032974)
		(width 0.088646)
		(layer "In4.Cu")
		(net "M_C_CPU1_SA_DQS_DP<5>")
	)
	(arc
		(start 90.872564 -277.024338)
		(mid 90.59256 -276.957084)
		(end 90.315796 -277.03653)
		(width 0.088646)
		(layer "In4.Cu")
		(net "M_C_CPU1_SA_DQS_DP<5>")
	)
	(arc
		(start 92.76715 -277.032974)
		(mid 92.492951 -276.957139)
		(end 92.216478 -277.024338)
		(width 0.088646)
		(layer "In4.Cu")
		(net "M_C_CPU1_SA_DQS_DP<5>")
	)
	(arc
		(start 89.09939 -280.766012)
		(mid 89.099557 -280.777188)
		(end 89.09939 -280.788364)
		(width 0.088646)
		(layer "In4.Cu")
		(net "M_C_CPU1_SA_DQS_DP<5>")
	)
	(arc
		(start 85.623654 -283.544264)
		(mid 85.474818 -283.642867)
		(end 85.340444 -283.760418)
		(width 0.088646)
		(layer "In4.Cu")
		(net "M_C_CPU1_SA_DQS_DP<5>")
	)
	(arc
		(start 88.629744 -281.59202)
		(mid 88.442445 -281.916461)
		(end 88.067896 -281.916378)
		(width 0.088646)
		(layer "In4.Cu")
		(net "M_C_CPU1_SA_DQS_DP<5>")
	)
	(arc
		(start 87.49665 -281.919934)
		(mid 87.294063 -282.126285)
		(end 87.220044 -282.405836)
		(width 0.088646)
		(layer "In4.Cu")
		(net "M_C_CPU1_SA_DQS_DP<5>")
	)
	(arc
		(start 89.099644 -279.150318)
		(mid 89.051965 -279.333218)
		(end 88.921082 -279.469596)
		(width 0.088646)
		(layer "In4.Cu")
		(net "M_C_CPU1_SA_DQS_DP<5>")
	)
	(arc
		(start 88.912192 -279.474676)
		(mid 88.62944 -279.964324)
		(end 88.912192 -280.453846)
		(width 0.088646)
		(layer "In4.Cu")
		(net "M_C_CPU1_SA_DQS_DP<5>")
	)
	(arc
		(start 89.569544 -278.336502)
		(mid 89.521865 -278.519402)
		(end 89.390982 -278.65578)
		(width 0.088646)
		(layer "In4.Cu")
		(net "M_C_CPU1_SA_DQS_DP<5>")
	)
	(arc
		(start 87.220044 -282.414472)
		(mid 87.02917 -282.732281)
		(end 86.65845 -282.730194)
		(width 0.088646)
		(layer "In4.Cu")
		(net "M_C_CPU1_SA_DQS_DP<5>")
	)
	(arc
		(start 92.201746 -277.032974)
		(mid 92.014548 -277.083117)
		(end 91.82735 -277.032974)
		(width 0.088646)
		(layer "In4.Cu")
		(net "M_C_CPU1_SA_DQS_DP<5>")
	)
	(arc
		(start 88.067896 -281.916378)
		(mid 87.791337 -281.840635)
		(end 87.51316 -281.910282)
		(width 0.088646)
		(layer "In4.Cu")
		(net "M_C_CPU1_SA_DQS_DP<5>")
	)
	(arc
		(start 93.982794 -277.435818)
		(mid 93.890633 -277.203046)
		(end 93.70695 -277.032974)
		(width 0.088646)
		(layer "In4.Cu")
		(net "M_C_CPU1_SA_DQS_DP<5>")
	)
	(arc
		(start 88.906096 -281.106118)
		(mid 88.703683 -281.312531)
		(end 88.629744 -281.59202)
		(width 0.088646)
		(layer "In4.Cu")
		(net "M_C_CPU1_SA_DQS_DP<5>")
	)
	(arc
		(start 88.921082 -280.458926)
		(mid 89.048893 -280.590019)
		(end 89.09939 -280.766012)
		(width 0.088646)
		(layer "In4.Cu")
		(net "M_C_CPU1_SA_DQS_DP<5>")
	)
	(arc
		(start 85.810598 -283.22651)
		(mid 85.758909 -283.409981)
		(end 85.623654 -283.544264)
		(width 0.088646)
		(layer "In4.Cu")
		(net "M_C_CPU1_SA_DQS_DP<5>")
	)
	(arc
		(start 89.851992 -277.84679)
		(mid 89.649706 -278.045771)
		(end 89.569544 -278.31796)
		(width 0.088646)
		(layer "In4.Cu")
		(net "M_C_CPU1_SA_DQS_DP<5>")
	)
	(segment
		(start 94.833694 -260.430518)
		(end 94.83344 -260.430772)
		(width 0.20066)
		(layer "F.Cu")
		(net "M_C_CPU1_SA_DQS_DP<4>")
	)
	(segment
		(start 25.715214 -275.680678)
		(end 25.976326 -275.94179)
		(width 0.20066)
		(layer "F.Cu")
		(net "M_C_CPU1_SA_DQS_DP<4>")
	)
	(segment
		(start 26.45029 -275.94179)
		(end 28.205684 -275.94179)
		(width 0.1016)
		(layer "F.Cu")
		(net "M_C_CPU1_SA_DQS_DP<4>")
	)
	(segment
		(start 29.693362 -275.255482)
		(end 29.962094 -275.255482)
		(width 0.20066)
		(layer "F.Cu")
		(net "M_C_CPU1_SA_DQS_DP<4>")
	)
	(segment
		(start 23.766018 -275.516594)
		(end 24.02713 -275.255482)
		(width 0.20066)
		(layer "F.Cu")
		(net "M_C_CPU1_SA_DQS_DP<4>")
	)
	(segment
		(start 25.976326 -275.94179)
		(end 26.074116 -275.94179)
		(width 0.20066)
		(layer "F.Cu")
		(net "M_C_CPU1_SA_DQS_DP<4>")
	)
	(segment
		(start 30.223206 -275.516594)
		(end 30.771846 -275.516594)
		(width 0.20066)
		(layer "F.Cu")
		(net "M_C_CPU1_SA_DQS_DP<4>")
	)
	(segment
		(start 23.228046 -275.516594)
		(end 23.766018 -275.516594)
		(width 0.20066)
		(layer "F.Cu")
		(net "M_C_CPU1_SA_DQS_DP<4>")
	)
	(segment
		(start 28.681172 -275.94179)
		(end 28.942284 -275.680678)
		(width 0.20066)
		(layer "F.Cu")
		(net "M_C_CPU1_SA_DQS_DP<4>")
	)
	(segment
		(start 31.876746 -275.516594)
		(end 30.771846 -275.516594)
		(width 0.20066)
		(layer "F.Cu")
		(net "M_C_CPU1_SA_DQS_DP<4>")
	)
	(segment
		(start 29.962094 -275.255482)
		(end 30.223206 -275.516594)
		(width 0.20066)
		(layer "F.Cu")
		(net "M_C_CPU1_SA_DQS_DP<4>")
	)
	(segment
		(start 28.594812 -275.94179)
		(end 28.681172 -275.94179)
		(width 0.20066)
		(layer "F.Cu")
		(net "M_C_CPU1_SA_DQS_DP<4>")
	)
	(segment
		(start 24.452072 -275.255482)
		(end 25.088088 -275.680678)
		(width 0.20066)
		(layer "F.Cu")
		(net "M_C_CPU1_SA_DQS_DP<4>")
	)
	(segment
		(start 94.833694 -259.894832)
		(end 94.833694 -260.430518)
		(width 0.20066)
		(layer "F.Cu")
		(net "M_C_CPU1_SA_DQS_DP<4>")
	)
	(segment
		(start 25.088088 -275.680678)
		(end 25.715214 -275.680678)
		(width 0.20066)
		(layer "F.Cu")
		(net "M_C_CPU1_SA_DQS_DP<4>")
	)
	(segment
		(start 28.205684 -275.94179)
		(end 28.594812 -275.94179)
		(width 0.101854)
		(layer "F.Cu")
		(net "M_C_CPU1_SA_DQS_DP<4>")
	)
	(segment
		(start 24.02713 -275.255482)
		(end 24.452072 -275.255482)
		(width 0.20066)
		(layer "F.Cu")
		(net "M_C_CPU1_SA_DQS_DP<4>")
	)
	(segment
		(start 26.074116 -275.94179)
		(end 26.45029 -275.94179)
		(width 0.101854)
		(layer "F.Cu")
		(net "M_C_CPU1_SA_DQS_DP<4>")
	)
	(segment
		(start 29.268166 -275.680678)
		(end 29.693362 -275.255482)
		(width 0.20066)
		(layer "F.Cu")
		(net "M_C_CPU1_SA_DQS_DP<4>")
	)
	(segment
		(start 28.942284 -275.680678)
		(end 29.268166 -275.680678)
		(width 0.20066)
		(layer "F.Cu")
		(net "M_C_CPU1_SA_DQS_DP<4>")
	)
	(segment
		(start 46.097444 -267.146024)
		(end 45.641514 -267.450824)
		(width 0.18288)
		(layer "In6.Cu")
		(net "M_C_CPU1_SA_DQS_DP<4>")
	)
	(segment
		(start 82.741008 -261.022338)
		(end 82.681318 -261.082028)
		(width 0.088646)
		(layer "In6.Cu")
		(net "M_C_CPU1_SA_DQS_DP<4>")
	)
	(segment
		(start 71.20509 -262.499856)
		(end 70.65645 -262.499856)
		(width 0.18288)
		(layer "In6.Cu")
		(net "M_C_CPU1_SA_DQS_DP<4>")
	)
	(segment
		(start 71.32955 -262.375396)
		(end 71.20509 -262.499856)
		(width 0.18288)
		(layer "In6.Cu")
		(net "M_C_CPU1_SA_DQS_DP<4>")
	)
	(segment
		(start 40.40251 -271.15643)
		(end 39.895272 -271.366488)
		(width 0.18288)
		(layer "In6.Cu")
		(net "M_C_CPU1_SA_DQS_DP<4>")
	)
	(segment
		(start 57.874916 -265.815826)
		(end 57.326276 -265.815826)
		(width 0.18288)
		(layer "In6.Cu")
		(net "M_C_CPU1_SA_DQS_DP<4>")
	)
	(segment
		(start 43.039538 -269.371572)
		(end 43.039538 -269.547594)
		(width 0.18288)
		(layer "In6.Cu")
		(net "M_C_CPU1_SA_DQS_DP<4>")
	)
	(segment
		(start 68.23202 -263.099296)
		(end 68.16471 -263.26211)
		(width 0.18288)
		(layer "In6.Cu")
		(net "M_C_CPU1_SA_DQS_DP<4>")
	)
	(segment
		(start 69.476366 -262.584946)
		(end 69.409056 -262.74776)
		(width 0.18288)
		(layer "In6.Cu")
		(net "M_C_CPU1_SA_DQS_DP<4>")
	)
	(segment
		(start 53.445918 -266.316714)
		(end 51.607212 -266.316714)
		(width 0.18288)
		(layer "In6.Cu")
		(net "M_C_CPU1_SA_DQS_DP<4>")
	)
	(segment
		(start 39.732712 -271.299178)
		(end 39.225982 -271.508982)
		(width 0.18288)
		(layer "In6.Cu")
		(net "M_C_CPU1_SA_DQS_DP<4>")
	)
	(segment
		(start 93.156278 -260.11505)
		(end 93.141546 -260.106414)
		(width 0.088646)
		(layer "In6.Cu")
		(net "M_C_CPU1_SA_DQS_DP<4>")
	)
	(segment
		(start 57.999376 -265.691366)
		(end 57.874916 -265.815826)
		(width 0.18288)
		(layer "In6.Cu")
		(net "M_C_CPU1_SA_DQS_DP<4>")
	)
	(segment
		(start 35.749738 -273.392392)
		(end 35.460432 -273.103086)
		(width 0.18288)
		(layer "In6.Cu")
		(net "M_C_CPU1_SA_DQS_DP<4>")
	)
	(segment
		(start 66.250312 -263.918446)
		(end 65.479168 -264.237216)
		(width 0.18288)
		(layer "In6.Cu")
		(net "M_C_CPU1_SA_DQS_DP<4>")
	)
	(segment
		(start 51.331876 -266.59205)
		(end 50.875692 -266.59205)
		(width 0.18288)
		(layer "In6.Cu")
		(net "M_C_CPU1_SA_DQS_DP<4>")
	)
	(segment
		(start 83.899502 -260.32206)
		(end 83.199224 -261.022338)
		(width 0.088646)
		(layer "In6.Cu")
		(net "M_C_CPU1_SA_DQS_DP<4>")
	)
	(segment
		(start 61.92393 -264.850626)
		(end 61.240416 -265.133836)
		(width 0.18288)
		(layer "In6.Cu")
		(net "M_C_CPU1_SA_DQS_DP<4>")
	)
	(segment
		(start 56.302148 -265.691366)
		(end 54.792118 -266.316714)
		(width 0.18288)
		(layer "In6.Cu")
		(net "M_C_CPU1_SA_DQS_DP<4>")
	)
	(segment
		(start 39.895272 -271.366488)
		(end 39.732712 -271.299178)
		(width 0.18288)
		(layer "In6.Cu")
		(net "M_C_CPU1_SA_DQS_DP<4>")
	)
	(segment
		(start 64.226694 -265.206226)
		(end 63.297308 -265.206226)
		(width 0.18288)
		(layer "In6.Cu")
		(net "M_C_CPU1_SA_DQS_DP<4>")
	)
	(segment
		(start 69.98335 -262.375396)
		(end 69.476366 -262.584946)
		(width 0.18288)
		(layer "In6.Cu")
		(net "M_C_CPU1_SA_DQS_DP<4>")
	)
	(segment
		(start 82.681318 -261.082028)
		(end 82.65795 -261.082028)
		(width 0.088646)
		(layer "In6.Cu")
		(net "M_C_CPU1_SA_DQS_DP<4>")
	)
	(segment
		(start 45.60697 -267.62329)
		(end 45.150786 -267.928344)
		(width 0.18288)
		(layer "In6.Cu")
		(net "M_C_CPU1_SA_DQS_DP<4>")
	)
	(segment
		(start 46.490636 -267.1572)
		(end 46.482508 -267.1572)
		(width 0.18288)
		(layer "In6.Cu")
		(net "M_C_CPU1_SA_DQS_DP<4>")
	)
	(segment
		(start 92.211906 -260.11251)
		(end 92.201492 -260.106414)
		(width 0.088646)
		(layer "In6.Cu")
		(net "M_C_CPU1_SA_DQS_DP<4>")
	)
	(segment
		(start 61.240416 -265.133836)
		(end 60.279026 -266.095226)
		(width 0.18288)
		(layer "In6.Cu")
		(net "M_C_CPU1_SA_DQS_DP<4>")
	)
	(segment
		(start 82.65795 -261.082028)
		(end 81.335118 -261.082028)
		(width 0.18288)
		(layer "In6.Cu")
		(net "M_C_CPU1_SA_DQS_DP<4>")
	)
	(segment
		(start 32.97174 -275.244306)
		(end 32.149034 -275.244306)
		(width 0.18288)
		(layer "In6.Cu")
		(net "M_C_CPU1_SA_DQS_DP<4>")
	)
	(segment
		(start 36.49726 -273.138646)
		(end 36.243514 -273.392392)
		(width 0.18288)
		(layer "In6.Cu")
		(net "M_C_CPU1_SA_DQS_DP<4>")
	)
	(segment
		(start 47.518828 -267.155168)
		(end 47.231808 -267.442188)
		(width 0.18288)
		(layer "In6.Cu")
		(net "M_C_CPU1_SA_DQS_DP<4>")
	)
	(segment
		(start 35.11296 -273.103086)
		(end 32.97174 -275.244306)
		(width 0.18288)
		(layer "In6.Cu")
		(net "M_C_CPU1_SA_DQS_DP<4>")
	)
	(segment
		(start 84.072476 -260.32206)
		(end 83.899502 -260.32206)
		(width 0.088646)
		(layer "In6.Cu")
		(net "M_C_CPU1_SA_DQS_DP<4>")
	)
	(segment
		(start 37.093652 -273.138646)
		(end 36.49726 -273.138646)
		(width 0.18288)
		(layer "In6.Cu")
		(net "M_C_CPU1_SA_DQS_DP<4>")
	)
	(segment
		(start 45.641514 -267.450824)
		(end 45.60697 -267.62329)
		(width 0.18288)
		(layer "In6.Cu")
		(net "M_C_CPU1_SA_DQS_DP<4>")
	)
	(segment
		(start 36.243514 -273.392392)
		(end 35.749738 -273.392392)
		(width 0.18288)
		(layer "In6.Cu")
		(net "M_C_CPU1_SA_DQS_DP<4>")
	)
	(segment
		(start 37.951156 -272.783554)
		(end 37.093652 -273.138646)
		(width 0.18288)
		(layer "In6.Cu")
		(net "M_C_CPU1_SA_DQS_DP<4>")
	)
	(segment
		(start 35.460432 -273.103086)
		(end 35.11296 -273.103086)
		(width 0.18288)
		(layer "In6.Cu")
		(net "M_C_CPU1_SA_DQS_DP<4>")
	)
	(segment
		(start 50.875692 -266.59205)
		(end 50.590704 -266.307062)
		(width 0.18288)
		(layer "In6.Cu")
		(net "M_C_CPU1_SA_DQS_DP<4>")
	)
	(segment
		(start 70.65645 -262.499856)
		(end 70.53199 -262.375396)
		(width 0.18288)
		(layer "In6.Cu")
		(net "M_C_CPU1_SA_DQS_DP<4>")
	)
	(segment
		(start 59.735212 -266.095226)
		(end 58.760868 -265.691366)
		(width 0.18288)
		(layer "In6.Cu")
		(net "M_C_CPU1_SA_DQS_DP<4>")
	)
	(segment
		(start 40.46982 -270.993616)
		(end 40.40251 -271.15643)
		(width 0.18288)
		(layer "In6.Cu")
		(net "M_C_CPU1_SA_DQS_DP<4>")
	)
	(segment
		(start 68.16471 -263.26211)
		(end 67.657218 -263.47166)
		(width 0.18288)
		(layer "In6.Cu")
		(net "M_C_CPU1_SA_DQS_DP<4>")
	)
	(segment
		(start 66.412872 -263.98601)
		(end 66.250312 -263.918446)
		(width 0.18288)
		(layer "In6.Cu")
		(net "M_C_CPU1_SA_DQS_DP<4>")
	)
	(segment
		(start 78.212188 -262.375396)
		(end 71.32955 -262.375396)
		(width 0.18288)
		(layer "In6.Cu")
		(net "M_C_CPU1_SA_DQS_DP<4>")
	)
	(segment
		(start 88.452706 -260.11251)
		(end 88.442292 -260.106414)
		(width 0.088646)
		(layer "In6.Cu")
		(net "M_C_CPU1_SA_DQS_DP<4>")
	)
	(segment
		(start 67.657218 -263.47166)
		(end 67.494658 -263.404096)
		(width 0.18288)
		(layer "In6.Cu")
		(net "M_C_CPU1_SA_DQS_DP<4>")
	)
	(segment
		(start 63.297308 -265.206226)
		(end 62.438788 -264.850626)
		(width 0.18288)
		(layer "In6.Cu")
		(net "M_C_CPU1_SA_DQS_DP<4>")
	)
	(segment
		(start 32.149034 -275.244306)
		(end 31.876746 -275.516594)
		(width 0.18288)
		(layer "In6.Cu")
		(net "M_C_CPU1_SA_DQS_DP<4>")
	)
	(segment
		(start 57.201816 -265.691366)
		(end 56.302148 -265.691366)
		(width 0.18288)
		(layer "In6.Cu")
		(net "M_C_CPU1_SA_DQS_DP<4>")
	)
	(segment
		(start 50.590704 -266.307062)
		(end 49.914048 -266.307062)
		(width 0.18288)
		(layer "In6.Cu")
		(net "M_C_CPU1_SA_DQS_DP<4>")
	)
	(segment
		(start 43.039538 -269.547594)
		(end 42.651426 -269.935706)
		(width 0.18288)
		(layer "In6.Cu")
		(net "M_C_CPU1_SA_DQS_DP<4>")
	)
	(segment
		(start 67.494658 -263.404096)
		(end 66.987674 -263.613646)
		(width 0.18288)
		(layer "In6.Cu")
		(net "M_C_CPU1_SA_DQS_DP<4>")
	)
	(segment
		(start 58.760868 -265.691366)
		(end 57.999376 -265.691366)
		(width 0.18288)
		(layer "In6.Cu")
		(net "M_C_CPU1_SA_DQS_DP<4>")
	)
	(segment
		(start 46.471332 -267.146024)
		(end 46.097444 -267.146024)
		(width 0.18288)
		(layer "In6.Cu")
		(net "M_C_CPU1_SA_DQS_DP<4>")
	)
	(segment
		(start 62.438788 -264.850626)
		(end 61.92393 -264.850626)
		(width 0.18288)
		(layer "In6.Cu")
		(net "M_C_CPU1_SA_DQS_DP<4>")
	)
	(segment
		(start 60.279026 -266.095226)
		(end 59.735212 -266.095226)
		(width 0.18288)
		(layer "In6.Cu")
		(net "M_C_CPU1_SA_DQS_DP<4>")
	)
	(segment
		(start 81.335118 -261.082028)
		(end 78.212188 -262.375396)
		(width 0.18288)
		(layer "In6.Cu")
		(net "M_C_CPU1_SA_DQS_DP<4>")
	)
	(segment
		(start 49.065942 -267.155168)
		(end 47.518828 -267.155168)
		(width 0.18288)
		(layer "In6.Cu")
		(net "M_C_CPU1_SA_DQS_DP<4>")
	)
	(segment
		(start 42.475404 -269.935706)
		(end 42.087546 -270.323564)
		(width 0.18288)
		(layer "In6.Cu")
		(net "M_C_CPU1_SA_DQS_DP<4>")
	)
	(segment
		(start 66.987674 -263.613646)
		(end 66.920364 -263.77646)
		(width 0.18288)
		(layer "In6.Cu")
		(net "M_C_CPU1_SA_DQS_DP<4>")
	)
	(segment
		(start 42.651426 -269.935706)
		(end 42.475404 -269.935706)
		(width 0.18288)
		(layer "In6.Cu")
		(net "M_C_CPU1_SA_DQS_DP<4>")
	)
	(segment
		(start 68.901564 -262.95731)
		(end 68.739004 -262.889746)
		(width 0.18288)
		(layer "In6.Cu")
		(net "M_C_CPU1_SA_DQS_DP<4>")
	)
	(segment
		(start 49.914048 -266.307062)
		(end 49.065942 -267.155168)
		(width 0.18288)
		(layer "In6.Cu")
		(net "M_C_CPU1_SA_DQS_DP<4>")
	)
	(segment
		(start 94.081346 -260.10616)
		(end 94.081092 -260.106414)
		(width 0.088646)
		(layer "In6.Cu")
		(net "M_C_CPU1_SA_DQS_DP<4>")
	)
	(segment
		(start 69.409056 -262.74776)
		(end 68.901564 -262.95731)
		(width 0.18288)
		(layer "In6.Cu")
		(net "M_C_CPU1_SA_DQS_DP<4>")
	)
	(segment
		(start 45.150786 -267.928344)
		(end 44.978066 -267.894054)
		(width 0.18288)
		(layer "In6.Cu")
		(net "M_C_CPU1_SA_DQS_DP<4>")
	)
	(segment
		(start 43.588432 -268.822678)
		(end 43.039538 -269.371572)
		(width 0.18288)
		(layer "In6.Cu")
		(net "M_C_CPU1_SA_DQS_DP<4>")
	)
	(segment
		(start 66.920364 -263.77646)
		(end 66.412872 -263.98601)
		(width 0.18288)
		(layer "In6.Cu")
		(net "M_C_CPU1_SA_DQS_DP<4>")
	)
	(segment
		(start 53.570378 -266.441174)
		(end 53.445918 -266.316714)
		(width 0.18288)
		(layer "In6.Cu")
		(net "M_C_CPU1_SA_DQS_DP<4>")
	)
	(segment
		(start 89.397078 -260.11505)
		(end 89.382346 -260.106414)
		(width 0.088646)
		(layer "In6.Cu")
		(net "M_C_CPU1_SA_DQS_DP<4>")
	)
	(segment
		(start 54.792118 -266.316714)
		(end 54.243478 -266.316714)
		(width 0.18288)
		(layer "In6.Cu")
		(net "M_C_CPU1_SA_DQS_DP<4>")
	)
	(segment
		(start 54.119018 -266.441174)
		(end 53.570378 -266.441174)
		(width 0.18288)
		(layer "In6.Cu")
		(net "M_C_CPU1_SA_DQS_DP<4>")
	)
	(segment
		(start 44.978066 -267.894054)
		(end 43.588432 -268.822678)
		(width 0.18288)
		(layer "In6.Cu")
		(net "M_C_CPU1_SA_DQS_DP<4>")
	)
	(segment
		(start 91.827096 -260.106414)
		(end 91.816682 -260.11251)
		(width 0.088646)
		(layer "In6.Cu")
		(net "M_C_CPU1_SA_DQS_DP<4>")
	)
	(segment
		(start 70.53199 -262.375396)
		(end 69.98335 -262.375396)
		(width 0.18288)
		(layer "In6.Cu")
		(net "M_C_CPU1_SA_DQS_DP<4>")
	)
	(segment
		(start 57.326276 -265.815826)
		(end 57.201816 -265.691366)
		(width 0.18288)
		(layer "In6.Cu")
		(net "M_C_CPU1_SA_DQS_DP<4>")
	)
	(segment
		(start 64.709548 -265.00709)
		(end 64.226694 -265.206226)
		(width 0.18288)
		(layer "In6.Cu")
		(net "M_C_CPU1_SA_DQS_DP<4>")
	)
	(segment
		(start 83.199224 -261.022338)
		(end 82.741008 -261.022338)
		(width 0.088646)
		(layer "In6.Cu")
		(net "M_C_CPU1_SA_DQS_DP<4>")
	)
	(segment
		(start 46.482508 -267.1572)
		(end 46.471332 -267.146024)
		(width 0.18288)
		(layer "In6.Cu")
		(net "M_C_CPU1_SA_DQS_DP<4>")
	)
	(segment
		(start 42.087546 -270.323564)
		(end 40.46982 -270.993616)
		(width 0.18288)
		(layer "In6.Cu")
		(net "M_C_CPU1_SA_DQS_DP<4>")
	)
	(segment
		(start 65.479168 -264.237216)
		(end 64.709548 -265.00709)
		(width 0.18288)
		(layer "In6.Cu")
		(net "M_C_CPU1_SA_DQS_DP<4>")
	)
	(segment
		(start 84.23021 -260.16585)
		(end 84.072476 -260.32206)
		(width 0.088646)
		(layer "In6.Cu")
		(net "M_C_CPU1_SA_DQS_DP<4>")
	)
	(segment
		(start 94.80169 -260.314948)
		(end 94.762828 -260.29285)
		(width 0.088646)
		(layer "In6.Cu")
		(net "M_C_CPU1_SA_DQS_DP<4>")
	)
	(segment
		(start 90.336878 -260.11505)
		(end 90.322146 -260.106414)
		(width 0.088646)
		(layer "In6.Cu")
		(net "M_C_CPU1_SA_DQS_DP<4>")
	)
	(segment
		(start 54.243478 -266.316714)
		(end 54.119018 -266.441174)
		(width 0.18288)
		(layer "In6.Cu")
		(net "M_C_CPU1_SA_DQS_DP<4>")
	)
	(segment
		(start 51.607212 -266.316714)
		(end 51.331876 -266.59205)
		(width 0.18288)
		(layer "In6.Cu")
		(net "M_C_CPU1_SA_DQS_DP<4>")
	)
	(segment
		(start 47.231808 -267.442188)
		(end 46.775624 -267.442188)
		(width 0.18288)
		(layer "In6.Cu")
		(net "M_C_CPU1_SA_DQS_DP<4>")
	)
	(segment
		(start 84.230718 -260.165596)
		(end 84.23021 -260.16585)
		(width 0.088646)
		(layer "In6.Cu")
		(net "M_C_CPU1_SA_DQS_DP<4>")
	)
	(segment
		(start 46.775624 -267.442188)
		(end 46.490636 -267.1572)
		(width 0.18288)
		(layer "In6.Cu")
		(net "M_C_CPU1_SA_DQS_DP<4>")
	)
	(segment
		(start 68.739004 -262.889746)
		(end 68.23202 -263.099296)
		(width 0.18288)
		(layer "In6.Cu")
		(net "M_C_CPU1_SA_DQS_DP<4>")
	)
	(segment
		(start 94.83344 -260.430772)
		(end 94.80169 -260.314948)
		(width 0.088646)
		(layer "In6.Cu")
		(net "M_C_CPU1_SA_DQS_DP<4>")
	)
	(segment
		(start 94.334584 -260.251956)
		(end 94.081346 -260.10616)
		(width 0.088646)
		(layer "In6.Cu")
		(net "M_C_CPU1_SA_DQS_DP<4>")
	)
	(segment
		(start 94.608142 -260.251956)
		(end 94.334584 -260.251956)
		(width 0.088646)
		(layer "In6.Cu")
		(net "M_C_CPU1_SA_DQS_DP<4>")
	)
	(segment
		(start 93.706696 -260.106414)
		(end 93.70695 -260.106414)
		(width 0.088646)
		(layer "In6.Cu")
		(net "M_C_CPU1_SA_DQS_DP<4>")
	)
	(segment
		(start 39.225982 -271.508982)
		(end 37.951156 -272.783554)
		(width 0.18288)
		(layer "In6.Cu")
		(net "M_C_CPU1_SA_DQS_DP<4>")
	)
	(arc
		(start 93.141546 -260.106414)
		(mid 92.954348 -260.056271)
		(end 92.76715 -260.106414)
		(width 0.088646)
		(layer "In6.Cu")
		(net "M_C_CPU1_SA_DQS_DP<4>")
	)
	(arc
		(start 86.562692 -260.106414)
		(mid 86.375494 -260.056271)
		(end 86.188296 -260.106414)
		(width 0.088646)
		(layer "In6.Cu")
		(net "M_C_CPU1_SA_DQS_DP<4>")
	)
	(arc
		(start 94.762828 -260.29285)
		(mid 94.688143 -260.262345)
		(end 94.608142 -260.251956)
		(width 0.088646)
		(layer "In6.Cu")
		(net "M_C_CPU1_SA_DQS_DP<4>")
	)
	(arc
		(start 85.622892 -260.106414)
		(mid 85.435694 -260.056271)
		(end 85.248496 -260.106414)
		(width 0.088646)
		(layer "In6.Cu")
		(net "M_C_CPU1_SA_DQS_DP<4>")
	)
	(arc
		(start 84.308696 -260.106414)
		(mid 84.267766 -260.133447)
		(end 84.230718 -260.165596)
		(width 0.088646)
		(layer "In6.Cu")
		(net "M_C_CPU1_SA_DQS_DP<4>")
	)
	(arc
		(start 91.261946 -260.106414)
		(mid 91.074748 -260.056271)
		(end 90.88755 -260.106414)
		(width 0.088646)
		(layer "In6.Cu")
		(net "M_C_CPU1_SA_DQS_DP<4>")
	)
	(arc
		(start 90.88755 -260.106414)
		(mid 90.613351 -260.182249)
		(end 90.336878 -260.11505)
		(width 0.088646)
		(layer "In6.Cu")
		(net "M_C_CPU1_SA_DQS_DP<4>")
	)
	(arc
		(start 89.94775 -260.106414)
		(mid 89.673551 -260.182249)
		(end 89.397078 -260.11505)
		(width 0.088646)
		(layer "In6.Cu")
		(net "M_C_CPU1_SA_DQS_DP<4>")
	)
	(arc
		(start 92.76715 -260.106414)
		(mid 92.490337 -260.182284)
		(end 92.211906 -260.11251)
		(width 0.088646)
		(layer "In6.Cu")
		(net "M_C_CPU1_SA_DQS_DP<4>")
	)
	(arc
		(start 91.816682 -260.11251)
		(mid 91.538504 -260.182233)
		(end 91.261946 -260.106414)
		(width 0.088646)
		(layer "In6.Cu")
		(net "M_C_CPU1_SA_DQS_DP<4>")
	)
	(arc
		(start 93.70695 -260.106414)
		(mid 93.432751 -260.182249)
		(end 93.156278 -260.11505)
		(width 0.088646)
		(layer "In6.Cu")
		(net "M_C_CPU1_SA_DQS_DP<4>")
	)
	(arc
		(start 85.248496 -260.106414)
		(mid 84.965794 -260.18219)
		(end 84.683092 -260.106414)
		(width 0.088646)
		(layer "In6.Cu")
		(net "M_C_CPU1_SA_DQS_DP<4>")
	)
	(arc
		(start 94.081092 -260.106414)
		(mid 93.893894 -260.056271)
		(end 93.706696 -260.106414)
		(width 0.088646)
		(layer "In6.Cu")
		(net "M_C_CPU1_SA_DQS_DP<4>")
	)
	(arc
		(start 88.442292 -260.106414)
		(mid 88.255094 -260.056271)
		(end 88.067896 -260.106414)
		(width 0.088646)
		(layer "In6.Cu")
		(net "M_C_CPU1_SA_DQS_DP<4>")
	)
	(arc
		(start 86.188296 -260.106414)
		(mid 85.905594 -260.18219)
		(end 85.622892 -260.106414)
		(width 0.088646)
		(layer "In6.Cu")
		(net "M_C_CPU1_SA_DQS_DP<4>")
	)
	(arc
		(start 90.322146 -260.106414)
		(mid 90.134948 -260.056271)
		(end 89.94775 -260.106414)
		(width 0.088646)
		(layer "In6.Cu")
		(net "M_C_CPU1_SA_DQS_DP<4>")
	)
	(arc
		(start 87.128096 -260.106414)
		(mid 86.845394 -260.18219)
		(end 86.562692 -260.106414)
		(width 0.088646)
		(layer "In6.Cu")
		(net "M_C_CPU1_SA_DQS_DP<4>")
	)
	(arc
		(start 92.201492 -260.106414)
		(mid 92.014294 -260.056271)
		(end 91.827096 -260.106414)
		(width 0.088646)
		(layer "In6.Cu")
		(net "M_C_CPU1_SA_DQS_DP<4>")
	)
	(arc
		(start 87.502492 -260.106414)
		(mid 87.315294 -260.056271)
		(end 87.128096 -260.106414)
		(width 0.088646)
		(layer "In6.Cu")
		(net "M_C_CPU1_SA_DQS_DP<4>")
	)
	(arc
		(start 89.382346 -260.106414)
		(mid 89.195148 -260.056271)
		(end 89.00795 -260.106414)
		(width 0.088646)
		(layer "In6.Cu")
		(net "M_C_CPU1_SA_DQS_DP<4>")
	)
	(arc
		(start 84.683092 -260.106414)
		(mid 84.495894 -260.056271)
		(end 84.308696 -260.106414)
		(width 0.088646)
		(layer "In6.Cu")
		(net "M_C_CPU1_SA_DQS_DP<4>")
	)
	(arc
		(start 89.00795 -260.106414)
		(mid 88.731137 -260.182284)
		(end 88.452706 -260.11251)
		(width 0.088646)
		(layer "In6.Cu")
		(net "M_C_CPU1_SA_DQS_DP<4>")
	)
	(arc
		(start 88.067896 -260.106414)
		(mid 87.785194 -260.18219)
		(end 87.502492 -260.106414)
		(width 0.088646)
		(layer "In6.Cu")
		(net "M_C_CPU1_SA_DQS_DP<4>")
	)
	(segment
		(start 30.223206 -284.866588)
		(end 30.771846 -284.866588)
		(width 0.20066)
		(layer "F.Cu")
		(net "M_C_CPU1_SA_DQS_DP<3>")
	)
	(segment
		(start 23.228046 -284.866588)
		(end 23.766018 -284.866588)
		(width 0.20066)
		(layer "F.Cu")
		(net "M_C_CPU1_SA_DQS_DP<3>")
	)
	(segment
		(start 26.45029 -285.291784)
		(end 28.205684 -285.291784)
		(width 0.1016)
		(layer "F.Cu")
		(net "M_C_CPU1_SA_DQS_DP<3>")
	)
	(segment
		(start 31.876746 -284.866588)
		(end 30.771846 -284.866588)
		(width 0.20066)
		(layer "F.Cu")
		(net "M_C_CPU1_SA_DQS_DP<3>")
	)
	(segment
		(start 24.452072 -284.605476)
		(end 25.088088 -285.030672)
		(width 0.20066)
		(layer "F.Cu")
		(net "M_C_CPU1_SA_DQS_DP<3>")
	)
	(segment
		(start 28.681172 -285.291784)
		(end 28.942284 -285.030672)
		(width 0.20066)
		(layer "F.Cu")
		(net "M_C_CPU1_SA_DQS_DP<3>")
	)
	(segment
		(start 95.773494 -264.778236)
		(end 95.773748 -265.314176)
		(width 0.20066)
		(layer "F.Cu")
		(net "M_C_CPU1_SA_DQS_DP<3>")
	)
	(segment
		(start 28.942284 -285.030672)
		(end 29.268166 -285.030672)
		(width 0.20066)
		(layer "F.Cu")
		(net "M_C_CPU1_SA_DQS_DP<3>")
	)
	(segment
		(start 25.985724 -285.301182)
		(end 26.20391 -285.301182)
		(width 0.20066)
		(layer "F.Cu")
		(net "M_C_CPU1_SA_DQS_DP<3>")
	)
	(segment
		(start 29.268166 -285.030672)
		(end 29.693362 -284.605476)
		(width 0.20066)
		(layer "F.Cu")
		(net "M_C_CPU1_SA_DQS_DP<3>")
	)
	(segment
		(start 29.962094 -284.605476)
		(end 30.223206 -284.866588)
		(width 0.20066)
		(layer "F.Cu")
		(net "M_C_CPU1_SA_DQS_DP<3>")
	)
	(segment
		(start 28.529026 -285.291784)
		(end 28.681172 -285.291784)
		(width 0.20066)
		(layer "F.Cu")
		(net "M_C_CPU1_SA_DQS_DP<3>")
	)
	(segment
		(start 26.20391 -285.301182)
		(end 26.213308 -285.291784)
		(width 0.101854)
		(layer "F.Cu")
		(net "M_C_CPU1_SA_DQS_DP<3>")
	)
	(segment
		(start 26.213308 -285.291784)
		(end 26.45029 -285.291784)
		(width 0.101854)
		(layer "F.Cu")
		(net "M_C_CPU1_SA_DQS_DP<3>")
	)
	(segment
		(start 29.693362 -284.605476)
		(end 29.962094 -284.605476)
		(width 0.20066)
		(layer "F.Cu")
		(net "M_C_CPU1_SA_DQS_DP<3>")
	)
	(segment
		(start 25.715214 -285.030672)
		(end 25.985724 -285.301182)
		(width 0.20066)
		(layer "F.Cu")
		(net "M_C_CPU1_SA_DQS_DP<3>")
	)
	(segment
		(start 28.205684 -285.291784)
		(end 28.529026 -285.291784)
		(width 0.101854)
		(layer "F.Cu")
		(net "M_C_CPU1_SA_DQS_DP<3>")
	)
	(segment
		(start 24.02713 -284.605476)
		(end 24.452072 -284.605476)
		(width 0.20066)
		(layer "F.Cu")
		(net "M_C_CPU1_SA_DQS_DP<3>")
	)
	(segment
		(start 23.766018 -284.866588)
		(end 24.02713 -284.605476)
		(width 0.20066)
		(layer "F.Cu")
		(net "M_C_CPU1_SA_DQS_DP<3>")
	)
	(segment
		(start 25.088088 -285.030672)
		(end 25.715214 -285.030672)
		(width 0.20066)
		(layer "F.Cu")
		(net "M_C_CPU1_SA_DQS_DP<3>")
	)
	(segment
		(start 33.809178 -284.383226)
		(end 33.138364 -284.383226)
		(width 0.18288)
		(layer "In6.Cu")
		(net "M_C_CPU1_SA_DQS_DP<3>")
	)
	(segment
		(start 47.524416 -281.612086)
		(end 47.244508 -281.891994)
		(width 0.18288)
		(layer "In6.Cu")
		(net "M_C_CPU1_SA_DQS_DP<3>")
	)
	(segment
		(start 91.357196 -265.803634)
		(end 91.342464 -265.81227)
		(width 0.088646)
		(layer "In6.Cu")
		(net "M_C_CPU1_SA_DQS_DP<3>")
	)
	(segment
		(start 83.062572 -267.960856)
		(end 83.039204 -267.960856)
		(width 0.088646)
		(layer "In6.Cu")
		(net "M_C_CPU1_SA_DQS_DP<3>")
	)
	(segment
		(start 35.486848 -284.999938)
		(end 34.726626 -284.999938)
		(width 0.18288)
		(layer "In6.Cu")
		(net "M_C_CPU1_SA_DQS_DP<3>")
	)
	(segment
		(start 83.039204 -267.960856)
		(end 82.334354 -267.960856)
		(width 0.18288)
		(layer "In6.Cu")
		(net "M_C_CPU1_SA_DQS_DP<3>")
	)
	(segment
		(start 32.650176 -284.58541)
		(end 32.157924 -284.58541)
		(width 0.18288)
		(layer "In6.Cu")
		(net "M_C_CPU1_SA_DQS_DP<3>")
	)
	(segment
		(start 48.646842 -281.612086)
		(end 47.524416 -281.612086)
		(width 0.18288)
		(layer "In6.Cu")
		(net "M_C_CPU1_SA_DQS_DP<3>")
	)
	(segment
		(start 47.244508 -281.891994)
		(end 46.76648 -281.891994)
		(width 0.18288)
		(layer "In6.Cu")
		(net "M_C_CPU1_SA_DQS_DP<3>")
	)
	(segment
		(start 84.240624 -266.937236)
		(end 84.240624 -267.44295)
		(width 0.088646)
		(layer "In6.Cu")
		(net "M_C_CPU1_SA_DQS_DP<3>")
	)
	(segment
		(start 95.433388 -265.404092)
		(end 95.008192 -265.6459)
		(width 0.088646)
		(layer "In6.Cu")
		(net "M_C_CPU1_SA_DQS_DP<3>")
	)
	(segment
		(start 50.866548 -281.041856)
		(end 50.58791 -280.763218)
		(width 0.18288)
		(layer "In6.Cu")
		(net "M_C_CPU1_SA_DQS_DP<3>")
	)
	(segment
		(start 35.778694 -285.291784)
		(end 35.486848 -284.999938)
		(width 0.18288)
		(layer "In6.Cu")
		(net "M_C_CPU1_SA_DQS_DP<3>")
	)
	(segment
		(start 83.122516 -267.900912)
		(end 83.062572 -267.960856)
		(width 0.088646)
		(layer "In6.Cu")
		(net "M_C_CPU1_SA_DQS_DP<3>")
	)
	(segment
		(start 49.277778 -281.350974)
		(end 48.646842 -281.612086)
		(width 0.18288)
		(layer "In6.Cu")
		(net "M_C_CPU1_SA_DQS_DP<3>")
	)
	(segment
		(start 67.928744 -275.92401)
		(end 65.366646 -276.986492)
		(width 0.18288)
		(layer "In6.Cu")
		(net "M_C_CPU1_SA_DQS_DP<3>")
	)
	(segment
		(start 85.640418 -265.86307)
		(end 85.370162 -266.133326)
		(width 0.088646)
		(layer "In6.Cu")
		(net "M_C_CPU1_SA_DQS_DP<3>")
	)
	(segment
		(start 51.624484 -280.761948)
		(end 51.344576 -281.041856)
		(width 0.18288)
		(layer "In6.Cu")
		(net "M_C_CPU1_SA_DQS_DP<3>")
	)
	(segment
		(start 50.58791 -280.763218)
		(end 50.271934 -280.763218)
		(width 0.18288)
		(layer "In6.Cu")
		(net "M_C_CPU1_SA_DQS_DP<3>")
	)
	(segment
		(start 85.044534 -266.133326)
		(end 84.240624 -266.937236)
		(width 0.088646)
		(layer "In6.Cu")
		(net "M_C_CPU1_SA_DQS_DP<3>")
	)
	(segment
		(start 94.386146 -265.683238)
		(end 94.162626 -265.812016)
		(width 0.088646)
		(layer "In6.Cu")
		(net "M_C_CPU1_SA_DQS_DP<3>")
	)
	(segment
		(start 94.741746 -265.683238)
		(end 94.386146 -265.683238)
		(width 0.088646)
		(layer "In6.Cu")
		(net "M_C_CPU1_SA_DQS_DP<3>")
	)
	(segment
		(start 51.344576 -281.041856)
		(end 50.866548 -281.041856)
		(width 0.18288)
		(layer "In6.Cu")
		(net "M_C_CPU1_SA_DQS_DP<3>")
	)
	(segment
		(start 94.803722 -265.687556)
		(end 94.746572 -265.680698)
		(width 0.088646)
		(layer "In6.Cu")
		(net "M_C_CPU1_SA_DQS_DP<3>")
	)
	(segment
		(start 93.236796 -265.803888)
		(end 93.222064 -265.812524)
		(width 0.088646)
		(layer "In6.Cu")
		(net "M_C_CPU1_SA_DQS_DP<3>")
	)
	(segment
		(start 36.25723 -285.291784)
		(end 35.778694 -285.291784)
		(width 0.18288)
		(layer "In6.Cu")
		(net "M_C_CPU1_SA_DQS_DP<3>")
	)
	(segment
		(start 64.395858 -277.957026)
		(end 63.707518 -277.957026)
		(width 0.18288)
		(layer "In6.Cu")
		(net "M_C_CPU1_SA_DQS_DP<3>")
	)
	(segment
		(start 46.475396 -281.60091)
		(end 46.200314 -281.60091)
		(width 0.18288)
		(layer "In6.Cu")
		(net "M_C_CPU1_SA_DQS_DP<3>")
	)
	(segment
		(start 34.726626 -284.999938)
		(end 34.322004 -284.595824)
		(width 0.18288)
		(layer "In6.Cu")
		(net "M_C_CPU1_SA_DQS_DP<3>")
	)
	(segment
		(start 63.707518 -277.957026)
		(end 62.531752 -277.470108)
		(width 0.18288)
		(layer "In6.Cu")
		(net "M_C_CPU1_SA_DQS_DP<3>")
	)
	(segment
		(start 33.138364 -284.383226)
		(end 32.650176 -284.58541)
		(width 0.18288)
		(layer "In6.Cu")
		(net "M_C_CPU1_SA_DQS_DP<3>")
	)
	(segment
		(start 94.746572 -265.680698)
		(end 94.741746 -265.683238)
		(width 0.088646)
		(layer "In6.Cu")
		(net "M_C_CPU1_SA_DQS_DP<3>")
	)
	(segment
		(start 36.531804 -285.01721)
		(end 36.25723 -285.291784)
		(width 0.18288)
		(layer "In6.Cu")
		(net "M_C_CPU1_SA_DQS_DP<3>")
	)
	(segment
		(start 54.70398 -280.761948)
		(end 51.624484 -280.761948)
		(width 0.18288)
		(layer "In6.Cu")
		(net "M_C_CPU1_SA_DQS_DP<3>")
	)
	(segment
		(start 45.838618 -281.751024)
		(end 45.137832 -282.45181)
		(width 0.18288)
		(layer "In6.Cu")
		(net "M_C_CPU1_SA_DQS_DP<3>")
	)
	(segment
		(start 88.537796 -265.803634)
		(end 88.537796 -265.803888)
		(width 0.088646)
		(layer "In6.Cu")
		(net "M_C_CPU1_SA_DQS_DP<3>")
	)
	(segment
		(start 58.277506 -278.173688)
		(end 56.34355 -278.173688)
		(width 0.18288)
		(layer "In6.Cu")
		(net "M_C_CPU1_SA_DQS_DP<3>")
	)
	(segment
		(start 71.334376 -272.518378)
		(end 67.928744 -275.92401)
		(width 0.18288)
		(layer "In6.Cu")
		(net "M_C_CPU1_SA_DQS_DP<3>")
	)
	(segment
		(start 55.857648 -278.65959)
		(end 55.187596 -280.278332)
		(width 0.18288)
		(layer "In6.Cu")
		(net "M_C_CPU1_SA_DQS_DP<3>")
	)
	(segment
		(start 82.334354 -267.960856)
		(end 71.334376 -272.518378)
		(width 0.18288)
		(layer "In6.Cu")
		(net "M_C_CPU1_SA_DQS_DP<3>")
	)
	(segment
		(start 34.322004 -284.595824)
		(end 33.809178 -284.383226)
		(width 0.18288)
		(layer "In6.Cu")
		(net "M_C_CPU1_SA_DQS_DP<3>")
	)
	(segment
		(start 59.975496 -277.470108)
		(end 58.277506 -278.173688)
		(width 0.18288)
		(layer "In6.Cu")
		(net "M_C_CPU1_SA_DQS_DP<3>")
	)
	(segment
		(start 39.76116 -285.01721)
		(end 36.531804 -285.01721)
		(width 0.18288)
		(layer "In6.Cu")
		(net "M_C_CPU1_SA_DQS_DP<3>")
	)
	(segment
		(start 56.34355 -278.173688)
		(end 55.857648 -278.65959)
		(width 0.18288)
		(layer "In6.Cu")
		(net "M_C_CPU1_SA_DQS_DP<3>")
	)
	(segment
		(start 42.354246 -283.604462)
		(end 41.776396 -284.182312)
		(width 0.18288)
		(layer "In6.Cu")
		(net "M_C_CPU1_SA_DQS_DP<3>")
	)
	(segment
		(start 83.782662 -267.900912)
		(end 83.122516 -267.900912)
		(width 0.088646)
		(layer "In6.Cu")
		(net "M_C_CPU1_SA_DQS_DP<3>")
	)
	(segment
		(start 41.776396 -284.182312)
		(end 39.76116 -285.01721)
		(width 0.18288)
		(layer "In6.Cu")
		(net "M_C_CPU1_SA_DQS_DP<3>")
	)
	(segment
		(start 46.200314 -281.60091)
		(end 45.838618 -281.751024)
		(width 0.18288)
		(layer "In6.Cu")
		(net "M_C_CPU1_SA_DQS_DP<3>")
	)
	(segment
		(start 46.76648 -281.891994)
		(end 46.475396 -281.60091)
		(width 0.18288)
		(layer "In6.Cu")
		(net "M_C_CPU1_SA_DQS_DP<3>")
	)
	(segment
		(start 62.531752 -277.470108)
		(end 59.975496 -277.470108)
		(width 0.18288)
		(layer "In6.Cu")
		(net "M_C_CPU1_SA_DQS_DP<3>")
	)
	(segment
		(start 84.240624 -267.44295)
		(end 83.782662 -267.900912)
		(width 0.088646)
		(layer "In6.Cu")
		(net "M_C_CPU1_SA_DQS_DP<3>")
	)
	(segment
		(start 92.671392 -265.803888)
		(end 92.671392 -265.803634)
		(width 0.088646)
		(layer "In6.Cu")
		(net "M_C_CPU1_SA_DQS_DP<3>")
	)
	(segment
		(start 65.366646 -276.986492)
		(end 64.395858 -277.957026)
		(width 0.18288)
		(layer "In6.Cu")
		(net "M_C_CPU1_SA_DQS_DP<3>")
	)
	(segment
		(start 85.370162 -266.133326)
		(end 85.044534 -266.133326)
		(width 0.088646)
		(layer "In6.Cu")
		(net "M_C_CPU1_SA_DQS_DP<3>")
	)
	(segment
		(start 32.157924 -284.58541)
		(end 31.876746 -284.866588)
		(width 0.18288)
		(layer "In6.Cu")
		(net "M_C_CPU1_SA_DQS_DP<3>")
	)
	(segment
		(start 93.611446 -265.803634)
		(end 93.611192 -265.803888)
		(width 0.088646)
		(layer "In6.Cu")
		(net "M_C_CPU1_SA_DQS_DP<3>")
	)
	(segment
		(start 49.577752 -281.051)
		(end 49.277778 -281.350974)
		(width 0.18288)
		(layer "In6.Cu")
		(net "M_C_CPU1_SA_DQS_DP<3>")
	)
	(segment
		(start 45.137832 -282.45181)
		(end 42.354246 -283.604462)
		(width 0.18288)
		(layer "In6.Cu")
		(net "M_C_CPU1_SA_DQS_DP<3>")
	)
	(segment
		(start 55.187596 -280.278332)
		(end 54.70398 -280.761948)
		(width 0.18288)
		(layer "In6.Cu")
		(net "M_C_CPU1_SA_DQS_DP<3>")
	)
	(segment
		(start 50.271934 -280.763218)
		(end 49.577752 -281.051)
		(width 0.18288)
		(layer "In6.Cu")
		(net "M_C_CPU1_SA_DQS_DP<3>")
	)
	(arc
		(start 91.342464 -265.81227)
		(mid 91.065989 -265.87959)
		(end 90.791792 -265.803634)
		(width 0.088646)
		(layer "In6.Cu")
		(net "M_C_CPU1_SA_DQS_DP<3>")
	)
	(arc
		(start 90.791792 -265.803634)
		(mid 90.604594 -265.753491)
		(end 90.417396 -265.803634)
		(width 0.088646)
		(layer "In6.Cu")
		(net "M_C_CPU1_SA_DQS_DP<3>")
	)
	(arc
		(start 90.417396 -265.803634)
		(mid 90.134694 -265.87941)
		(end 89.851992 -265.803634)
		(width 0.088646)
		(layer "In6.Cu")
		(net "M_C_CPU1_SA_DQS_DP<3>")
	)
	(arc
		(start 87.972392 -265.803888)
		(mid 87.785194 -265.753745)
		(end 87.597996 -265.803888)
		(width 0.088646)
		(layer "In6.Cu")
		(net "M_C_CPU1_SA_DQS_DP<3>")
	)
	(arc
		(start 93.611192 -265.803888)
		(mid 93.423994 -265.753745)
		(end 93.236796 -265.803888)
		(width 0.088646)
		(layer "In6.Cu")
		(net "M_C_CPU1_SA_DQS_DP<3>")
	)
	(arc
		(start 88.537796 -265.803888)
		(mid 88.255094 -265.87963)
		(end 87.972392 -265.803888)
		(width 0.088646)
		(layer "In6.Cu")
		(net "M_C_CPU1_SA_DQS_DP<3>")
	)
	(arc
		(start 92.296996 -265.803634)
		(mid 92.014294 -265.87941)
		(end 91.731592 -265.803634)
		(width 0.088646)
		(layer "In6.Cu")
		(net "M_C_CPU1_SA_DQS_DP<3>")
	)
	(arc
		(start 94.162626 -265.812016)
		(mid 93.885961 -265.879487)
		(end 93.611446 -265.803634)
		(width 0.088646)
		(layer "In6.Cu")
		(net "M_C_CPU1_SA_DQS_DP<3>")
	)
	(arc
		(start 95.773748 -265.314176)
		(mid 95.597727 -265.337013)
		(end 95.433388 -265.404092)
		(width 0.088646)
		(layer "In6.Cu")
		(net "M_C_CPU1_SA_DQS_DP<3>")
	)
	(arc
		(start 87.032592 -265.803888)
		(mid 86.845394 -265.753745)
		(end 86.658196 -265.803888)
		(width 0.088646)
		(layer "In6.Cu")
		(net "M_C_CPU1_SA_DQS_DP<3>")
	)
	(arc
		(start 89.477596 -265.803634)
		(mid 89.194894 -265.87941)
		(end 88.912192 -265.803634)
		(width 0.088646)
		(layer "In6.Cu")
		(net "M_C_CPU1_SA_DQS_DP<3>")
	)
	(arc
		(start 93.222064 -265.812524)
		(mid 92.945623 -265.87969)
		(end 92.671392 -265.803888)
		(width 0.088646)
		(layer "In6.Cu")
		(net "M_C_CPU1_SA_DQS_DP<3>")
	)
	(arc
		(start 89.851992 -265.803634)
		(mid 89.664794 -265.753491)
		(end 89.477596 -265.803634)
		(width 0.088646)
		(layer "In6.Cu")
		(net "M_C_CPU1_SA_DQS_DP<3>")
	)
	(arc
		(start 88.912192 -265.803634)
		(mid 88.724994 -265.753491)
		(end 88.537796 -265.803634)
		(width 0.088646)
		(layer "In6.Cu")
		(net "M_C_CPU1_SA_DQS_DP<3>")
	)
	(arc
		(start 87.597996 -265.803888)
		(mid 87.315294 -265.87963)
		(end 87.032592 -265.803888)
		(width 0.088646)
		(layer "In6.Cu")
		(net "M_C_CPU1_SA_DQS_DP<3>")
	)
	(arc
		(start 85.718396 -265.803888)
		(mid 85.677466 -265.830921)
		(end 85.640418 -265.86307)
		(width 0.088646)
		(layer "In6.Cu")
		(net "M_C_CPU1_SA_DQS_DP<3>")
	)
	(arc
		(start 95.008192 -265.6459)
		(mid 94.90935 -265.68341)
		(end 94.803722 -265.687556)
		(width 0.088646)
		(layer "In6.Cu")
		(net "M_C_CPU1_SA_DQS_DP<3>")
	)
	(arc
		(start 86.658196 -265.803888)
		(mid 86.375494 -265.87963)
		(end 86.092792 -265.803888)
		(width 0.088646)
		(layer "In6.Cu")
		(net "M_C_CPU1_SA_DQS_DP<3>")
	)
	(arc
		(start 86.092792 -265.803888)
		(mid 85.905594 -265.753745)
		(end 85.718396 -265.803888)
		(width 0.088646)
		(layer "In6.Cu")
		(net "M_C_CPU1_SA_DQS_DP<3>")
	)
	(arc
		(start 91.731592 -265.803634)
		(mid 91.544394 -265.753491)
		(end 91.357196 -265.803634)
		(width 0.088646)
		(layer "In6.Cu")
		(net "M_C_CPU1_SA_DQS_DP<3>")
	)
	(arc
		(start 92.671392 -265.803634)
		(mid 92.484194 -265.753491)
		(end 92.296996 -265.803634)
		(width 0.088646)
		(layer "In6.Cu")
		(net "M_C_CPU1_SA_DQS_DP<3>")
	)
	(segment
		(start 29.268166 -294.380666)
		(end 29.693362 -293.95547)
		(width 0.20066)
		(layer "F.Cu")
		(net "M_C_CPU1_SA_DQS_DP<2>")
	)
	(segment
		(start 25.715214 -294.380666)
		(end 25.985724 -294.651176)
		(width 0.20066)
		(layer "F.Cu")
		(net "M_C_CPU1_SA_DQS_DP<2>")
	)
	(segment
		(start 28.942284 -294.380666)
		(end 29.268166 -294.380666)
		(width 0.20066)
		(layer "F.Cu")
		(net "M_C_CPU1_SA_DQS_DP<2>")
	)
	(segment
		(start 28.205684 -294.641778)
		(end 28.529026 -294.641778)
		(width 0.101854)
		(layer "F.Cu")
		(net "M_C_CPU1_SA_DQS_DP<2>")
	)
	(segment
		(start 25.985724 -294.651176)
		(end 26.20391 -294.651176)
		(width 0.20066)
		(layer "F.Cu")
		(net "M_C_CPU1_SA_DQS_DP<2>")
	)
	(segment
		(start 26.213308 -294.641778)
		(end 26.45029 -294.641778)
		(width 0.101854)
		(layer "F.Cu")
		(net "M_C_CPU1_SA_DQS_DP<2>")
	)
	(segment
		(start 24.02713 -293.95547)
		(end 24.452072 -293.95547)
		(width 0.20066)
		(layer "F.Cu")
		(net "M_C_CPU1_SA_DQS_DP<2>")
	)
	(segment
		(start 28.529026 -294.641778)
		(end 28.681172 -294.641778)
		(width 0.20066)
		(layer "F.Cu")
		(net "M_C_CPU1_SA_DQS_DP<2>")
	)
	(segment
		(start 29.962094 -293.95547)
		(end 30.223206 -294.216582)
		(width 0.20066)
		(layer "F.Cu")
		(net "M_C_CPU1_SA_DQS_DP<2>")
	)
	(segment
		(start 29.693362 -293.95547)
		(end 29.962094 -293.95547)
		(width 0.20066)
		(layer "F.Cu")
		(net "M_C_CPU1_SA_DQS_DP<2>")
	)
	(segment
		(start 92.484448 -267.219938)
		(end 92.484194 -267.755878)
		(width 0.20066)
		(layer "F.Cu")
		(net "M_C_CPU1_SA_DQS_DP<2>")
	)
	(segment
		(start 24.452072 -293.95547)
		(end 25.088088 -294.380666)
		(width 0.20066)
		(layer "F.Cu")
		(net "M_C_CPU1_SA_DQS_DP<2>")
	)
	(segment
		(start 31.876746 -294.216582)
		(end 30.771846 -294.216582)
		(width 0.20066)
		(layer "F.Cu")
		(net "M_C_CPU1_SA_DQS_DP<2>")
	)
	(segment
		(start 28.681172 -294.641778)
		(end 28.942284 -294.380666)
		(width 0.20066)
		(layer "F.Cu")
		(net "M_C_CPU1_SA_DQS_DP<2>")
	)
	(segment
		(start 25.088088 -294.380666)
		(end 25.715214 -294.380666)
		(width 0.20066)
		(layer "F.Cu")
		(net "M_C_CPU1_SA_DQS_DP<2>")
	)
	(segment
		(start 23.228046 -294.216582)
		(end 23.766018 -294.216582)
		(width 0.20066)
		(layer "F.Cu")
		(net "M_C_CPU1_SA_DQS_DP<2>")
	)
	(segment
		(start 26.20391 -294.651176)
		(end 26.213308 -294.641778)
		(width 0.101854)
		(layer "F.Cu")
		(net "M_C_CPU1_SA_DQS_DP<2>")
	)
	(segment
		(start 23.766018 -294.216582)
		(end 24.02713 -293.95547)
		(width 0.20066)
		(layer "F.Cu")
		(net "M_C_CPU1_SA_DQS_DP<2>")
	)
	(segment
		(start 30.223206 -294.216582)
		(end 30.771846 -294.216582)
		(width 0.20066)
		(layer "F.Cu")
		(net "M_C_CPU1_SA_DQS_DP<2>")
	)
	(segment
		(start 26.45029 -294.641778)
		(end 28.205684 -294.641778)
		(width 0.1016)
		(layer "F.Cu")
		(net "M_C_CPU1_SA_DQS_DP<2>")
	)
	(segment
		(start 92.143834 -267.845794)
		(end 91.718638 -268.087602)
		(width 0.088646)
		(layer "In4.Cu")
		(net "M_C_CPU1_SA_DQS_DP<2>")
	)
	(segment
		(start 83.698842 -269.563596)
		(end 83.401916 -269.563596)
		(width 0.088646)
		(layer "In4.Cu")
		(net "M_C_CPU1_SA_DQS_DP<2>")
	)
	(segment
		(start 65.299844 -289.07105)
		(end 64.072262 -289.315398)
		(width 0.18288)
		(layer "In4.Cu")
		(net "M_C_CPU1_SA_DQS_DP<2>")
	)
	(segment
		(start 84.913216 -268.56182)
		(end 84.549742 -268.712696)
		(width 0.088646)
		(layer "In4.Cu")
		(net "M_C_CPU1_SA_DQS_DP<2>")
	)
	(segment
		(start 91.452192 -268.12494)
		(end 91.096592 -268.12494)
		(width 0.088646)
		(layer "In4.Cu")
		(net "M_C_CPU1_SA_DQS_DP<2>")
	)
	(segment
		(start 46.772576 -295.491662)
		(end 46.49724 -295.216326)
		(width 0.18288)
		(layer "In4.Cu")
		(net "M_C_CPU1_SA_DQS_DP<2>")
	)
	(segment
		(start 48.834802 -294.953182)
		(end 48.186848 -294.953182)
		(width 0.18288)
		(layer "In4.Cu")
		(net "M_C_CPU1_SA_DQS_DP<2>")
	)
	(segment
		(start 50.239422 -294.370252)
		(end 48.834802 -294.953182)
		(width 0.18288)
		(layer "In4.Cu")
		(net "M_C_CPU1_SA_DQS_DP<2>")
	)
	(segment
		(start 64.072262 -289.315398)
		(end 61.263022 -290.47948)
		(width 0.18288)
		(layer "In4.Cu")
		(net "M_C_CPU1_SA_DQS_DP<2>")
	)
	(segment
		(start 69.903848 -284.726126)
		(end 66.59499 -288.034476)
		(width 0.18288)
		(layer "In4.Cu")
		(net "M_C_CPU1_SA_DQS_DP<2>")
	)
	(segment
		(start 51.281076 -294.641778)
		(end 50.872644 -294.641778)
		(width 0.18288)
		(layer "In4.Cu")
		(net "M_C_CPU1_SA_DQS_DP<2>")
	)
	(segment
		(start 90.321892 -268.245336)
		(end 90.322146 -268.245336)
		(width 0.088646)
		(layer "In4.Cu")
		(net "M_C_CPU1_SA_DQS_DP<2>")
	)
	(segment
		(start 33.180528 -293.68877)
		(end 32.922718 -293.94658)
		(width 0.18288)
		(layer "In4.Cu")
		(net "M_C_CPU1_SA_DQS_DP<2>")
	)
	(segment
		(start 50.872644 -294.641778)
		(end 50.601118 -294.370252)
		(width 0.18288)
		(layer "In4.Cu")
		(net "M_C_CPU1_SA_DQS_DP<2>")
	)
	(segment
		(start 36.254182 -294.641778)
		(end 35.782758 -294.641778)
		(width 0.18288)
		(layer "In4.Cu")
		(net "M_C_CPU1_SA_DQS_DP<2>")
	)
	(segment
		(start 85.248496 -268.245336)
		(end 85.247988 -268.24559)
		(width 0.088646)
		(layer "In4.Cu")
		(net "M_C_CPU1_SA_DQS_DP<2>")
	)
	(segment
		(start 65.925954 -288.707322)
		(end 65.747646 -288.88563)
		(width 0.18288)
		(layer "In4.Cu")
		(net "M_C_CPU1_SA_DQS_DP<2>")
	)
	(segment
		(start 47.415196 -295.22547)
		(end 47.149004 -295.491662)
		(width 0.18288)
		(layer "In4.Cu")
		(net "M_C_CPU1_SA_DQS_DP<2>")
	)
	(segment
		(start 39.497254 -294.373046)
		(end 36.522914 -294.373046)
		(width 0.18288)
		(layer "In4.Cu")
		(net "M_C_CPU1_SA_DQS_DP<2>")
	)
	(segment
		(start 32.922718 -293.94658)
		(end 32.146748 -293.94658)
		(width 0.18288)
		(layer "In4.Cu")
		(net "M_C_CPU1_SA_DQS_DP<2>")
	)
	(segment
		(start 61.263022 -290.47948)
		(end 59.588146 -292.153848)
		(width 0.18288)
		(layer "In4.Cu")
		(net "M_C_CPU1_SA_DQS_DP<2>")
	)
	(segment
		(start 56.881522 -293.275258)
		(end 53.456586 -293.275258)
		(width 0.18288)
		(layer "In4.Cu")
		(net "M_C_CPU1_SA_DQS_DP<2>")
	)
	(segment
		(start 52.345336 -294.386508)
		(end 51.536346 -294.386508)
		(width 0.18288)
		(layer "In4.Cu")
		(net "M_C_CPU1_SA_DQS_DP<2>")
	)
	(segment
		(start 59.588146 -292.153848)
		(end 56.881522 -293.275258)
		(width 0.18288)
		(layer "In4.Cu")
		(net "M_C_CPU1_SA_DQS_DP<2>")
	)
	(segment
		(start 89.951814 -268.242796)
		(end 89.947496 -268.245336)
		(width 0.088646)
		(layer "In4.Cu")
		(net "M_C_CPU1_SA_DQS_DP<2>")
	)
	(segment
		(start 47.149004 -295.491662)
		(end 46.772576 -295.491662)
		(width 0.18288)
		(layer "In4.Cu")
		(net "M_C_CPU1_SA_DQS_DP<2>")
	)
	(segment
		(start 34.191194 -293.68877)
		(end 33.180528 -293.68877)
		(width 0.18288)
		(layer "In4.Cu")
		(net "M_C_CPU1_SA_DQS_DP<2>")
	)
	(segment
		(start 34.881312 -294.378888)
		(end 34.191194 -293.68877)
		(width 0.18288)
		(layer "In4.Cu")
		(net "M_C_CPU1_SA_DQS_DP<2>")
	)
	(segment
		(start 84.549742 -268.712696)
		(end 83.698842 -269.563596)
		(width 0.088646)
		(layer "In4.Cu")
		(net "M_C_CPU1_SA_DQS_DP<2>")
	)
	(segment
		(start 89.011506 -268.24305)
		(end 89.007696 -268.245336)
		(width 0.088646)
		(layer "In4.Cu")
		(net "M_C_CPU1_SA_DQS_DP<2>")
	)
	(segment
		(start 71.668386 -280.466546)
		(end 69.903848 -284.726126)
		(width 0.18288)
		(layer "In4.Cu")
		(net "M_C_CPU1_SA_DQS_DP<2>")
	)
	(segment
		(start 66.59499 -288.443416)
		(end 66.331084 -288.707322)
		(width 0.18288)
		(layer "In4.Cu")
		(net "M_C_CPU1_SA_DQS_DP<2>")
	)
	(segment
		(start 50.601118 -294.370252)
		(end 50.239422 -294.370252)
		(width 0.18288)
		(layer "In4.Cu")
		(net "M_C_CPU1_SA_DQS_DP<2>")
	)
	(segment
		(start 85.170518 -268.304518)
		(end 84.913216 -268.56182)
		(width 0.088646)
		(layer "In4.Cu")
		(net "M_C_CPU1_SA_DQS_DP<2>")
	)
	(segment
		(start 89.006172 -268.246098)
		(end 89.001854 -268.248638)
		(width 0.088646)
		(layer "In4.Cu")
		(net "M_C_CPU1_SA_DQS_DP<2>")
	)
	(segment
		(start 88.442546 -268.245336)
		(end 88.442546 -268.245082)
		(width 0.088646)
		(layer "In4.Cu")
		(net "M_C_CPU1_SA_DQS_DP<2>")
	)
	(segment
		(start 35.519868 -294.378888)
		(end 34.881312 -294.378888)
		(width 0.18288)
		(layer "In4.Cu")
		(net "M_C_CPU1_SA_DQS_DP<2>")
	)
	(segment
		(start 89.007696 -268.245336)
		(end 89.006172 -268.246098)
		(width 0.088646)
		(layer "In4.Cu")
		(net "M_C_CPU1_SA_DQS_DP<2>")
	)
	(segment
		(start 91.457018 -268.1224)
		(end 91.452192 -268.12494)
		(width 0.088646)
		(layer "In4.Cu")
		(net "M_C_CPU1_SA_DQS_DP<2>")
	)
	(segment
		(start 32.146748 -293.94658)
		(end 31.876746 -294.216582)
		(width 0.18288)
		(layer "In4.Cu")
		(net "M_C_CPU1_SA_DQS_DP<2>")
	)
	(segment
		(start 82.511392 -269.62354)
		(end 71.668386 -280.466546)
		(width 0.18288)
		(layer "In4.Cu")
		(net "M_C_CPU1_SA_DQS_DP<2>")
	)
	(segment
		(start 47.91456 -295.22547)
		(end 47.415196 -295.22547)
		(width 0.18288)
		(layer "In4.Cu")
		(net "M_C_CPU1_SA_DQS_DP<2>")
	)
	(segment
		(start 44.350178 -293.696644)
		(end 41.12895 -293.696644)
		(width 0.18288)
		(layer "In4.Cu")
		(net "M_C_CPU1_SA_DQS_DP<2>")
	)
	(segment
		(start 51.536346 -294.386508)
		(end 51.281076 -294.641778)
		(width 0.18288)
		(layer "In4.Cu")
		(net "M_C_CPU1_SA_DQS_DP<2>")
	)
	(segment
		(start 91.096592 -268.12494)
		(end 90.873072 -268.253718)
		(width 0.088646)
		(layer "In4.Cu")
		(net "M_C_CPU1_SA_DQS_DP<2>")
	)
	(segment
		(start 35.782758 -294.641778)
		(end 35.519868 -294.378888)
		(width 0.18288)
		(layer "In4.Cu")
		(net "M_C_CPU1_SA_DQS_DP<2>")
	)
	(segment
		(start 88.442546 -268.245082)
		(end 88.442292 -268.245336)
		(width 0.088646)
		(layer "In4.Cu")
		(net "M_C_CPU1_SA_DQS_DP<2>")
	)
	(segment
		(start 46.49724 -295.216326)
		(end 45.86986 -295.216326)
		(width 0.18288)
		(layer "In4.Cu")
		(net "M_C_CPU1_SA_DQS_DP<2>")
	)
	(segment
		(start 41.12895 -293.696644)
		(end 39.497254 -294.373046)
		(width 0.18288)
		(layer "In4.Cu")
		(net "M_C_CPU1_SA_DQS_DP<2>")
	)
	(segment
		(start 36.522914 -294.373046)
		(end 36.254182 -294.641778)
		(width 0.18288)
		(layer "In4.Cu")
		(net "M_C_CPU1_SA_DQS_DP<2>")
	)
	(segment
		(start 66.59499 -288.034476)
		(end 66.59499 -288.443416)
		(width 0.18288)
		(layer "In4.Cu")
		(net "M_C_CPU1_SA_DQS_DP<2>")
	)
	(segment
		(start 83.318604 -269.62354)
		(end 82.511392 -269.62354)
		(width 0.18288)
		(layer "In4.Cu")
		(net "M_C_CPU1_SA_DQS_DP<2>")
	)
	(segment
		(start 66.331084 -288.707322)
		(end 65.925954 -288.707322)
		(width 0.18288)
		(layer "In4.Cu")
		(net "M_C_CPU1_SA_DQS_DP<2>")
	)
	(segment
		(start 91.514168 -268.129258)
		(end 91.457018 -268.1224)
		(width 0.088646)
		(layer "In4.Cu")
		(net "M_C_CPU1_SA_DQS_DP<2>")
	)
	(segment
		(start 48.186848 -294.953182)
		(end 47.91456 -295.22547)
		(width 0.18288)
		(layer "In4.Cu")
		(net "M_C_CPU1_SA_DQS_DP<2>")
	)
	(segment
		(start 53.456586 -293.275258)
		(end 52.345336 -294.386508)
		(width 0.18288)
		(layer "In4.Cu")
		(net "M_C_CPU1_SA_DQS_DP<2>")
	)
	(segment
		(start 65.747646 -288.88563)
		(end 65.299844 -289.07105)
		(width 0.18288)
		(layer "In4.Cu")
		(net "M_C_CPU1_SA_DQS_DP<2>")
	)
	(segment
		(start 83.401916 -269.563596)
		(end 83.341972 -269.62354)
		(width 0.088646)
		(layer "In4.Cu")
		(net "M_C_CPU1_SA_DQS_DP<2>")
	)
	(segment
		(start 83.341972 -269.62354)
		(end 83.318604 -269.62354)
		(width 0.088646)
		(layer "In4.Cu")
		(net "M_C_CPU1_SA_DQS_DP<2>")
	)
	(segment
		(start 45.86986 -295.216326)
		(end 44.350178 -293.696644)
		(width 0.18288)
		(layer "In4.Cu")
		(net "M_C_CPU1_SA_DQS_DP<2>")
	)
	(arc
		(start 89.001854 -268.248638)
		(mid 88.721749 -268.32108)
		(end 88.442546 -268.245336)
		(width 0.088646)
		(layer "In4.Cu")
		(net "M_C_CPU1_SA_DQS_DP<2>")
	)
	(arc
		(start 87.502492 -268.245336)
		(mid 87.315294 -268.195193)
		(end 87.128096 -268.245336)
		(width 0.088646)
		(layer "In4.Cu")
		(net "M_C_CPU1_SA_DQS_DP<2>")
	)
	(arc
		(start 86.562692 -268.245336)
		(mid 86.375494 -268.195193)
		(end 86.188296 -268.245336)
		(width 0.088646)
		(layer "In4.Cu")
		(net "M_C_CPU1_SA_DQS_DP<2>")
	)
	(arc
		(start 88.067896 -268.245336)
		(mid 87.785194 -268.321112)
		(end 87.502492 -268.245336)
		(width 0.088646)
		(layer "In4.Cu")
		(net "M_C_CPU1_SA_DQS_DP<2>")
	)
	(arc
		(start 90.873072 -268.253718)
		(mid 90.596407 -268.321189)
		(end 90.321892 -268.245336)
		(width 0.088646)
		(layer "In4.Cu")
		(net "M_C_CPU1_SA_DQS_DP<2>")
	)
	(arc
		(start 85.247988 -268.24559)
		(mid 85.207333 -268.272529)
		(end 85.170518 -268.304518)
		(width 0.088646)
		(layer "In4.Cu")
		(net "M_C_CPU1_SA_DQS_DP<2>")
	)
	(arc
		(start 91.718638 -268.087602)
		(mid 91.619796 -268.125112)
		(end 91.514168 -268.129258)
		(width 0.088646)
		(layer "In4.Cu")
		(net "M_C_CPU1_SA_DQS_DP<2>")
	)
	(arc
		(start 89.382346 -268.245336)
		(mid 89.197225 -268.195073)
		(end 89.011506 -268.24305)
		(width 0.088646)
		(layer "In4.Cu")
		(net "M_C_CPU1_SA_DQS_DP<2>")
	)
	(arc
		(start 85.622892 -268.245336)
		(mid 85.435694 -268.195193)
		(end 85.248496 -268.245336)
		(width 0.088646)
		(layer "In4.Cu")
		(net "M_C_CPU1_SA_DQS_DP<2>")
	)
	(arc
		(start 89.947496 -268.245336)
		(mid 89.664938 -268.320985)
		(end 89.382346 -268.245336)
		(width 0.088646)
		(layer "In4.Cu")
		(net "M_C_CPU1_SA_DQS_DP<2>")
	)
	(arc
		(start 90.322146 -268.245336)
		(mid 90.137309 -268.195075)
		(end 89.951814 -268.242796)
		(width 0.088646)
		(layer "In4.Cu")
		(net "M_C_CPU1_SA_DQS_DP<2>")
	)
	(arc
		(start 92.484194 -267.755878)
		(mid 92.308173 -267.778715)
		(end 92.143834 -267.845794)
		(width 0.088646)
		(layer "In4.Cu")
		(net "M_C_CPU1_SA_DQS_DP<2>")
	)
	(arc
		(start 86.188296 -268.245336)
		(mid 85.905594 -268.321112)
		(end 85.622892 -268.245336)
		(width 0.088646)
		(layer "In4.Cu")
		(net "M_C_CPU1_SA_DQS_DP<2>")
	)
	(arc
		(start 88.442292 -268.245336)
		(mid 88.255094 -268.195193)
		(end 88.067896 -268.245336)
		(width 0.088646)
		(layer "In4.Cu")
		(net "M_C_CPU1_SA_DQS_DP<2>")
	)
	(arc
		(start 87.128096 -268.245336)
		(mid 86.845394 -268.321112)
		(end 86.562692 -268.245336)
		(width 0.088646)
		(layer "In4.Cu")
		(net "M_C_CPU1_SA_DQS_DP<2>")
	)
	(segment
		(start 28.529026 -303.991772)
		(end 28.681172 -303.991772)
		(width 0.20066)
		(layer "F.Cu")
		(net "M_C_CPU1_SA_DQS_DP<1>")
	)
	(segment
		(start 95.773494 -269.66164)
		(end 95.773748 -270.19758)
		(width 0.20066)
		(layer "F.Cu")
		(net "M_C_CPU1_SA_DQS_DP<1>")
	)
	(segment
		(start 25.985724 -304.00117)
		(end 26.20391 -304.00117)
		(width 0.20066)
		(layer "F.Cu")
		(net "M_C_CPU1_SA_DQS_DP<1>")
	)
	(segment
		(start 24.02713 -303.305464)
		(end 24.452072 -303.305464)
		(width 0.20066)
		(layer "F.Cu")
		(net "M_C_CPU1_SA_DQS_DP<1>")
	)
	(segment
		(start 29.962094 -303.305464)
		(end 30.223206 -303.566576)
		(width 0.20066)
		(layer "F.Cu")
		(net "M_C_CPU1_SA_DQS_DP<1>")
	)
	(segment
		(start 29.693362 -303.305464)
		(end 29.962094 -303.305464)
		(width 0.20066)
		(layer "F.Cu")
		(net "M_C_CPU1_SA_DQS_DP<1>")
	)
	(segment
		(start 30.223206 -303.566576)
		(end 30.771846 -303.566576)
		(width 0.20066)
		(layer "F.Cu")
		(net "M_C_CPU1_SA_DQS_DP<1>")
	)
	(segment
		(start 31.876746 -303.566576)
		(end 30.771846 -303.566576)
		(width 0.20066)
		(layer "F.Cu")
		(net "M_C_CPU1_SA_DQS_DP<1>")
	)
	(segment
		(start 25.715214 -303.73066)
		(end 25.985724 -304.00117)
		(width 0.20066)
		(layer "F.Cu")
		(net "M_C_CPU1_SA_DQS_DP<1>")
	)
	(segment
		(start 23.766018 -303.566576)
		(end 24.02713 -303.305464)
		(width 0.20066)
		(layer "F.Cu")
		(net "M_C_CPU1_SA_DQS_DP<1>")
	)
	(segment
		(start 25.088088 -303.73066)
		(end 25.715214 -303.73066)
		(width 0.20066)
		(layer "F.Cu")
		(net "M_C_CPU1_SA_DQS_DP<1>")
	)
	(segment
		(start 28.681172 -303.991772)
		(end 28.942284 -303.73066)
		(width 0.20066)
		(layer "F.Cu")
		(net "M_C_CPU1_SA_DQS_DP<1>")
	)
	(segment
		(start 26.20391 -304.00117)
		(end 26.213308 -303.991772)
		(width 0.101854)
		(layer "F.Cu")
		(net "M_C_CPU1_SA_DQS_DP<1>")
	)
	(segment
		(start 23.228046 -303.566576)
		(end 23.766018 -303.566576)
		(width 0.20066)
		(layer "F.Cu")
		(net "M_C_CPU1_SA_DQS_DP<1>")
	)
	(segment
		(start 28.205684 -303.991772)
		(end 28.529026 -303.991772)
		(width 0.101854)
		(layer "F.Cu")
		(net "M_C_CPU1_SA_DQS_DP<1>")
	)
	(segment
		(start 29.268166 -303.73066)
		(end 29.693362 -303.305464)
		(width 0.20066)
		(layer "F.Cu")
		(net "M_C_CPU1_SA_DQS_DP<1>")
	)
	(segment
		(start 24.452072 -303.305464)
		(end 25.088088 -303.73066)
		(width 0.20066)
		(layer "F.Cu")
		(net "M_C_CPU1_SA_DQS_DP<1>")
	)
	(segment
		(start 28.942284 -303.73066)
		(end 29.268166 -303.73066)
		(width 0.20066)
		(layer "F.Cu")
		(net "M_C_CPU1_SA_DQS_DP<1>")
	)
	(segment
		(start 26.45029 -303.991772)
		(end 28.205684 -303.991772)
		(width 0.1016)
		(layer "F.Cu")
		(net "M_C_CPU1_SA_DQS_DP<1>")
	)
	(segment
		(start 26.213308 -303.991772)
		(end 26.45029 -303.991772)
		(width 0.101854)
		(layer "F.Cu")
		(net "M_C_CPU1_SA_DQS_DP<1>")
	)
	(segment
		(start 67.92976 -285.875984)
		(end 65.908428 -285.875984)
		(width 0.18288)
		(layer "In6.Cu")
		(net "M_C_CPU1_SA_DQS_DP<1>")
	)
	(segment
		(start 48.325278 -294.969438)
		(end 48.059848 -295.234868)
		(width 0.18288)
		(layer "In6.Cu")
		(net "M_C_CPU1_SA_DQS_DP<1>")
	)
	(segment
		(start 32.145478 -303.297844)
		(end 31.876746 -303.566576)
		(width 0.18288)
		(layer "In6.Cu")
		(net "M_C_CPU1_SA_DQS_DP<1>")
	)
	(segment
		(start 36.53409 -303.714912)
		(end 36.25723 -303.991772)
		(width 0.18288)
		(layer "In6.Cu")
		(net "M_C_CPU1_SA_DQS_DP<1>")
	)
	(segment
		(start 91.357196 -270.687038)
		(end 91.342464 -270.695674)
		(width 0.088646)
		(layer "In6.Cu")
		(net "M_C_CPU1_SA_DQS_DP<1>")
	)
	(segment
		(start 86.57336 -271.50695)
		(end 86.562946 -271.500854)
		(width 0.088646)
		(layer "In6.Cu")
		(net "M_C_CPU1_SA_DQS_DP<1>")
	)
	(segment
		(start 48.059848 -295.234868)
		(end 47.455836 -295.234868)
		(width 0.18288)
		(layer "In6.Cu")
		(net "M_C_CPU1_SA_DQS_DP<1>")
	)
	(segment
		(start 47.198788 -295.491916)
		(end 46.76648 -295.491916)
		(width 0.18288)
		(layer "In6.Cu")
		(net "M_C_CPU1_SA_DQS_DP<1>")
	)
	(segment
		(start 56.896508 -290.754054)
		(end 54.55285 -291.725096)
		(width 0.18288)
		(layer "In6.Cu")
		(net "M_C_CPU1_SA_DQS_DP<1>")
	)
	(segment
		(start 42.468038 -301.052484)
		(end 41.686226 -301.834296)
		(width 0.18288)
		(layer "In6.Cu")
		(net "M_C_CPU1_SA_DQS_DP<1>")
	)
	(segment
		(start 35.493198 -303.706276)
		(end 34.800032 -303.706276)
		(width 0.18288)
		(layer "In6.Cu")
		(net "M_C_CPU1_SA_DQS_DP<1>")
	)
	(segment
		(start 50.56251 -294.362632)
		(end 49.785016 -294.362632)
		(width 0.18288)
		(layer "In6.Cu")
		(net "M_C_CPU1_SA_DQS_DP<1>")
	)
	(segment
		(start 32.949896 -303.297844)
		(end 32.145478 -303.297844)
		(width 0.18288)
		(layer "In6.Cu")
		(net "M_C_CPU1_SA_DQS_DP<1>")
	)
	(segment
		(start 82.864452 -274.133056)
		(end 77.415644 -276.3901)
		(width 0.18288)
		(layer "In6.Cu")
		(net "M_C_CPU1_SA_DQS_DP<1>")
	)
	(segment
		(start 61.751464 -288.534094)
		(end 59.687206 -288.534094)
		(width 0.18288)
		(layer "In6.Cu")
		(net "M_C_CPU1_SA_DQS_DP<1>")
	)
	(segment
		(start 83.4263 -274.073112)
		(end 83.366356 -274.133056)
		(width 0.088646)
		(layer "In6.Cu")
		(net "M_C_CPU1_SA_DQS_DP<1>")
	)
	(segment
		(start 94.741746 -270.566642)
		(end 94.386146 -270.566642)
		(width 0.088646)
		(layer "In6.Cu")
		(net "M_C_CPU1_SA_DQS_DP<1>")
	)
	(segment
		(start 93.611446 -270.687038)
		(end 93.611192 -270.687038)
		(width 0.088646)
		(layer "In6.Cu")
		(net "M_C_CPU1_SA_DQS_DP<1>")
	)
	(segment
		(start 35.778694 -303.991772)
		(end 35.493198 -303.706276)
		(width 0.18288)
		(layer "In6.Cu")
		(net "M_C_CPU1_SA_DQS_DP<1>")
	)
	(segment
		(start 84.011516 -274.073112)
		(end 83.4263 -274.073112)
		(width 0.088646)
		(layer "In6.Cu")
		(net "M_C_CPU1_SA_DQS_DP<1>")
	)
	(segment
		(start 58.231024 -289.419538)
		(end 56.896508 -290.754054)
		(width 0.18288)
		(layer "In6.Cu")
		(net "M_C_CPU1_SA_DQS_DP<1>")
	)
	(segment
		(start 43.72483 -294.996616)
		(end 42.774616 -295.94683)
		(width 0.18288)
		(layer "In6.Cu")
		(net "M_C_CPU1_SA_DQS_DP<1>")
	)
	(segment
		(start 94.386146 -270.566642)
		(end 94.162626 -270.69542)
		(width 0.088646)
		(layer "In6.Cu")
		(net "M_C_CPU1_SA_DQS_DP<1>")
	)
	(segment
		(start 85.226652 -272.38325)
		(end 84.667344 -272.942558)
		(width 0.088646)
		(layer "In6.Cu")
		(net "M_C_CPU1_SA_DQS_DP<1>")
	)
	(segment
		(start 83.342988 -274.133056)
		(end 82.864452 -274.133056)
		(width 0.18288)
		(layer "In6.Cu")
		(net "M_C_CPU1_SA_DQS_DP<1>")
	)
	(segment
		(start 49.17821 -294.969438)
		(end 48.325278 -294.969438)
		(width 0.18288)
		(layer "In6.Cu")
		(net "M_C_CPU1_SA_DQS_DP<1>")
	)
	(segment
		(start 84.667344 -272.942558)
		(end 84.667344 -273.417284)
		(width 0.088646)
		(layer "In6.Cu")
		(net "M_C_CPU1_SA_DQS_DP<1>")
	)
	(segment
		(start 45.132244 -294.619934)
		(end 44.632372 -294.619934)
		(width 0.18288)
		(layer "In6.Cu")
		(net "M_C_CPU1_SA_DQS_DP<1>")
	)
	(segment
		(start 87.410544 -270.971518)
		(end 87.410544 -271.021302)
		(width 0.088646)
		(layer "In6.Cu")
		(net "M_C_CPU1_SA_DQS_DP<1>")
	)
	(segment
		(start 34.800032 -303.706276)
		(end 34.419794 -303.32553)
		(width 0.18288)
		(layer "In6.Cu")
		(net "M_C_CPU1_SA_DQS_DP<1>")
	)
	(segment
		(start 41.686226 -301.834296)
		(end 37.146992 -303.714912)
		(width 0.18288)
		(layer "In6.Cu")
		(net "M_C_CPU1_SA_DQS_DP<1>")
	)
	(segment
		(start 93.236796 -270.687038)
		(end 93.222064 -270.695674)
		(width 0.088646)
		(layer "In6.Cu")
		(net "M_C_CPU1_SA_DQS_DP<1>")
	)
	(segment
		(start 86.001098 -271.825212)
		(end 86.001098 -271.840706)
		(width 0.088646)
		(layer "In6.Cu")
		(net "M_C_CPU1_SA_DQS_DP<1>")
	)
	(segment
		(start 59.687206 -288.534094)
		(end 59.205368 -289.015932)
		(width 0.18288)
		(layer "In6.Cu")
		(net "M_C_CPU1_SA_DQS_DP<1>")
	)
	(segment
		(start 42.774616 -295.94683)
		(end 42.468038 -296.686986)
		(width 0.18288)
		(layer "In6.Cu")
		(net "M_C_CPU1_SA_DQS_DP<1>")
	)
	(segment
		(start 33.41116 -303.106836)
		(end 32.949896 -303.297844)
		(width 0.18288)
		(layer "In6.Cu")
		(net "M_C_CPU1_SA_DQS_DP<1>")
	)
	(segment
		(start 94.746572 -270.564102)
		(end 94.741746 -270.566642)
		(width 0.088646)
		(layer "In6.Cu")
		(net "M_C_CPU1_SA_DQS_DP<1>")
	)
	(segment
		(start 86.18855 -271.500854)
		(end 86.17966 -271.505934)
		(width 0.088646)
		(layer "In6.Cu")
		(net "M_C_CPU1_SA_DQS_DP<1>")
	)
	(segment
		(start 46.76648 -295.491916)
		(end 46.475396 -295.200832)
		(width 0.18288)
		(layer "In6.Cu")
		(net "M_C_CPU1_SA_DQS_DP<1>")
	)
	(segment
		(start 77.415644 -276.3901)
		(end 67.92976 -285.875984)
		(width 0.18288)
		(layer "In6.Cu")
		(net "M_C_CPU1_SA_DQS_DP<1>")
	)
	(segment
		(start 47.455836 -295.234868)
		(end 47.198788 -295.491916)
		(width 0.18288)
		(layer "In6.Cu")
		(net "M_C_CPU1_SA_DQS_DP<1>")
	)
	(segment
		(start 50.841402 -294.641524)
		(end 50.56251 -294.362632)
		(width 0.18288)
		(layer "In6.Cu")
		(net "M_C_CPU1_SA_DQS_DP<1>")
	)
	(segment
		(start 36.25723 -303.991772)
		(end 35.778694 -303.991772)
		(width 0.18288)
		(layer "In6.Cu")
		(net "M_C_CPU1_SA_DQS_DP<1>")
	)
	(segment
		(start 59.205368 -289.015932)
		(end 58.231024 -289.419538)
		(width 0.18288)
		(layer "In6.Cu")
		(net "M_C_CPU1_SA_DQS_DP<1>")
	)
	(segment
		(start 87.417656 -270.93672)
		(end 87.410544 -270.971518)
		(width 0.088646)
		(layer "In6.Cu")
		(net "M_C_CPU1_SA_DQS_DP<1>")
	)
	(segment
		(start 51.916584 -294.361362)
		(end 51.599084 -294.361362)
		(width 0.18288)
		(layer "In6.Cu")
		(net "M_C_CPU1_SA_DQS_DP<1>")
	)
	(segment
		(start 54.55285 -291.725096)
		(end 51.916584 -294.361362)
		(width 0.18288)
		(layer "In6.Cu")
		(net "M_C_CPU1_SA_DQS_DP<1>")
	)
	(segment
		(start 84.667344 -273.417284)
		(end 84.011516 -274.073112)
		(width 0.088646)
		(layer "In6.Cu")
		(net "M_C_CPU1_SA_DQS_DP<1>")
	)
	(segment
		(start 34.419794 -303.32553)
		(end 33.890204 -303.106836)
		(width 0.18288)
		(layer "In6.Cu")
		(net "M_C_CPU1_SA_DQS_DP<1>")
	)
	(segment
		(start 45.713142 -295.200832)
		(end 45.132244 -294.619934)
		(width 0.18288)
		(layer "In6.Cu")
		(net "M_C_CPU1_SA_DQS_DP<1>")
	)
	(segment
		(start 37.146992 -303.714912)
		(end 36.53409 -303.714912)
		(width 0.18288)
		(layer "In6.Cu")
		(net "M_C_CPU1_SA_DQS_DP<1>")
	)
	(segment
		(start 42.468038 -296.686986)
		(end 42.468038 -301.052484)
		(width 0.18288)
		(layer "In6.Cu")
		(net "M_C_CPU1_SA_DQS_DP<1>")
	)
	(segment
		(start 33.890204 -303.106836)
		(end 33.41116 -303.106836)
		(width 0.18288)
		(layer "In6.Cu")
		(net "M_C_CPU1_SA_DQS_DP<1>")
	)
	(segment
		(start 51.599084 -294.361362)
		(end 51.318922 -294.641524)
		(width 0.18288)
		(layer "In6.Cu")
		(net "M_C_CPU1_SA_DQS_DP<1>")
	)
	(segment
		(start 51.318922 -294.641524)
		(end 50.841402 -294.641524)
		(width 0.18288)
		(layer "In6.Cu")
		(net "M_C_CPU1_SA_DQS_DP<1>")
	)
	(segment
		(start 65.908428 -285.875984)
		(end 64.309752 -287.47466)
		(width 0.18288)
		(layer "In6.Cu")
		(net "M_C_CPU1_SA_DQS_DP<1>")
	)
	(segment
		(start 83.366356 -274.133056)
		(end 83.342988 -274.133056)
		(width 0.088646)
		(layer "In6.Cu")
		(net "M_C_CPU1_SA_DQS_DP<1>")
	)
	(segment
		(start 94.803722 -270.57096)
		(end 94.746572 -270.564102)
		(width 0.088646)
		(layer "In6.Cu")
		(net "M_C_CPU1_SA_DQS_DP<1>")
	)
	(segment
		(start 64.309752 -287.47466)
		(end 61.751464 -288.534094)
		(width 0.18288)
		(layer "In6.Cu")
		(net "M_C_CPU1_SA_DQS_DP<1>")
	)
	(segment
		(start 85.460078 -272.38325)
		(end 85.226652 -272.38325)
		(width 0.088646)
		(layer "In6.Cu")
		(net "M_C_CPU1_SA_DQS_DP<1>")
	)
	(segment
		(start 46.475396 -295.200832)
		(end 45.713142 -295.200832)
		(width 0.18288)
		(layer "In6.Cu")
		(net "M_C_CPU1_SA_DQS_DP<1>")
	)
	(segment
		(start 44.632372 -294.619934)
		(end 43.72483 -294.996616)
		(width 0.18288)
		(layer "In6.Cu")
		(net "M_C_CPU1_SA_DQS_DP<1>")
	)
	(segment
		(start 95.433388 -270.287496)
		(end 95.008192 -270.529304)
		(width 0.088646)
		(layer "In6.Cu")
		(net "M_C_CPU1_SA_DQS_DP<1>")
	)
	(segment
		(start 49.785016 -294.362632)
		(end 49.17821 -294.969438)
		(width 0.18288)
		(layer "In6.Cu")
		(net "M_C_CPU1_SA_DQS_DP<1>")
	)
	(arc
		(start 95.773748 -270.19758)
		(mid 95.597727 -270.220417)
		(end 95.433388 -270.287496)
		(width 0.088646)
		(layer "In6.Cu")
		(net "M_C_CPU1_SA_DQS_DP<1>")
	)
	(arc
		(start 86.001098 -271.840706)
		(mid 85.925483 -272.10773)
		(end 85.731858 -272.306542)
		(width 0.088646)
		(layer "In6.Cu")
		(net "M_C_CPU1_SA_DQS_DP<1>")
	)
	(arc
		(start 92.671392 -270.687038)
		(mid 92.484194 -270.636895)
		(end 92.296996 -270.687038)
		(width 0.088646)
		(layer "In6.Cu")
		(net "M_C_CPU1_SA_DQS_DP<1>")
	)
	(arc
		(start 87.128096 -271.500854)
		(mid 86.851537 -271.576597)
		(end 86.57336 -271.50695)
		(width 0.088646)
		(layer "In6.Cu")
		(net "M_C_CPU1_SA_DQS_DP<1>")
	)
	(arc
		(start 86.17966 -271.505934)
		(mid 86.048746 -271.642294)
		(end 86.001098 -271.825212)
		(width 0.088646)
		(layer "In6.Cu")
		(net "M_C_CPU1_SA_DQS_DP<1>")
	)
	(arc
		(start 91.342464 -270.695674)
		(mid 91.065989 -270.762994)
		(end 90.791792 -270.687038)
		(width 0.088646)
		(layer "In6.Cu")
		(net "M_C_CPU1_SA_DQS_DP<1>")
	)
	(arc
		(start 93.611192 -270.687038)
		(mid 93.423994 -270.636895)
		(end 93.236796 -270.687038)
		(width 0.088646)
		(layer "In6.Cu")
		(net "M_C_CPU1_SA_DQS_DP<1>")
	)
	(arc
		(start 95.008192 -270.529304)
		(mid 94.90935 -270.566814)
		(end 94.803722 -270.57096)
		(width 0.088646)
		(layer "In6.Cu")
		(net "M_C_CPU1_SA_DQS_DP<1>")
	)
	(arc
		(start 94.162626 -270.69542)
		(mid 93.885961 -270.762891)
		(end 93.611446 -270.687038)
		(width 0.088646)
		(layer "In6.Cu")
		(net "M_C_CPU1_SA_DQS_DP<1>")
	)
	(arc
		(start 88.912192 -270.687038)
		(mid 88.724994 -270.636895)
		(end 88.537796 -270.687038)
		(width 0.088646)
		(layer "In6.Cu")
		(net "M_C_CPU1_SA_DQS_DP<1>")
	)
	(arc
		(start 90.791792 -270.687038)
		(mid 90.604594 -270.636895)
		(end 90.417396 -270.687038)
		(width 0.088646)
		(layer "In6.Cu")
		(net "M_C_CPU1_SA_DQS_DP<1>")
	)
	(arc
		(start 87.972392 -270.687038)
		(mid 87.631089 -270.66983)
		(end 87.417656 -270.93672)
		(width 0.088646)
		(layer "In6.Cu")
		(net "M_C_CPU1_SA_DQS_DP<1>")
	)
	(arc
		(start 86.562946 -271.500854)
		(mid 86.375748 -271.450711)
		(end 86.18855 -271.500854)
		(width 0.088646)
		(layer "In6.Cu")
		(net "M_C_CPU1_SA_DQS_DP<1>")
	)
	(arc
		(start 87.410544 -271.021302)
		(mid 87.332433 -271.298251)
		(end 87.128096 -271.500854)
		(width 0.088646)
		(layer "In6.Cu")
		(net "M_C_CPU1_SA_DQS_DP<1>")
	)
	(arc
		(start 88.537796 -270.687038)
		(mid 88.255094 -270.762814)
		(end 87.972392 -270.687038)
		(width 0.088646)
		(layer "In6.Cu")
		(net "M_C_CPU1_SA_DQS_DP<1>")
	)
	(arc
		(start 90.417396 -270.687038)
		(mid 90.134694 -270.762814)
		(end 89.851992 -270.687038)
		(width 0.088646)
		(layer "In6.Cu")
		(net "M_C_CPU1_SA_DQS_DP<1>")
	)
	(arc
		(start 92.296996 -270.687038)
		(mid 92.014294 -270.762814)
		(end 91.731592 -270.687038)
		(width 0.088646)
		(layer "In6.Cu")
		(net "M_C_CPU1_SA_DQS_DP<1>")
	)
	(arc
		(start 85.731858 -272.306542)
		(mid 85.601293 -272.363758)
		(end 85.460078 -272.38325)
		(width 0.088646)
		(layer "In6.Cu")
		(net "M_C_CPU1_SA_DQS_DP<1>")
	)
	(arc
		(start 93.222064 -270.695674)
		(mid 92.945589 -270.762994)
		(end 92.671392 -270.687038)
		(width 0.088646)
		(layer "In6.Cu")
		(net "M_C_CPU1_SA_DQS_DP<1>")
	)
	(arc
		(start 89.851992 -270.687038)
		(mid 89.664794 -270.636895)
		(end 89.477596 -270.687038)
		(width 0.088646)
		(layer "In6.Cu")
		(net "M_C_CPU1_SA_DQS_DP<1>")
	)
	(arc
		(start 89.477596 -270.687038)
		(mid 89.194894 -270.762814)
		(end 88.912192 -270.687038)
		(width 0.088646)
		(layer "In6.Cu")
		(net "M_C_CPU1_SA_DQS_DP<1>")
	)
	(arc
		(start 91.731592 -270.687038)
		(mid 91.544394 -270.636895)
		(end 91.357196 -270.687038)
		(width 0.088646)
		(layer "In6.Cu")
		(net "M_C_CPU1_SA_DQS_DP<1>")
	)
	(segment
		(start 92.484448 -276.986492)
		(end 92.484448 -277.522178)
		(width 0.20066)
		(layer "F.Cu")
		(net "M_C_CPU1_SA_DQS_DP<0>")
	)
	(segment
		(start 92.484448 -277.522178)
		(end 92.484194 -277.522432)
		(width 0.20066)
		(layer "F.Cu")
		(net "M_C_CPU1_SA_DQS_DP<0>")
	)
	(segment
		(start 25.088088 -313.080654)
		(end 25.715214 -313.080654)
		(width 0.20066)
		(layer "F.Cu")
		(net "M_C_CPU1_SA_DQS_DP<0>")
	)
	(segment
		(start 24.452072 -312.655458)
		(end 25.088088 -313.080654)
		(width 0.20066)
		(layer "F.Cu")
		(net "M_C_CPU1_SA_DQS_DP<0>")
	)
	(segment
		(start 26.45029 -313.341766)
		(end 28.205684 -313.341766)
		(width 0.1016)
		(layer "F.Cu")
		(net "M_C_CPU1_SA_DQS_DP<0>")
	)
	(segment
		(start 29.962094 -312.655458)
		(end 30.223206 -312.91657)
		(width 0.20066)
		(layer "F.Cu")
		(net "M_C_CPU1_SA_DQS_DP<0>")
	)
	(segment
		(start 26.213308 -313.341766)
		(end 26.45029 -313.341766)
		(width 0.101854)
		(layer "F.Cu")
		(net "M_C_CPU1_SA_DQS_DP<0>")
	)
	(segment
		(start 28.205684 -313.341766)
		(end 28.529026 -313.341766)
		(width 0.101854)
		(layer "F.Cu")
		(net "M_C_CPU1_SA_DQS_DP<0>")
	)
	(segment
		(start 29.268166 -313.080654)
		(end 29.693362 -312.655458)
		(width 0.20066)
		(layer "F.Cu")
		(net "M_C_CPU1_SA_DQS_DP<0>")
	)
	(segment
		(start 23.228046 -312.91657)
		(end 23.766018 -312.91657)
		(width 0.20066)
		(layer "F.Cu")
		(net "M_C_CPU1_SA_DQS_DP<0>")
	)
	(segment
		(start 28.942284 -313.080654)
		(end 29.268166 -313.080654)
		(width 0.20066)
		(layer "F.Cu")
		(net "M_C_CPU1_SA_DQS_DP<0>")
	)
	(segment
		(start 23.766018 -312.91657)
		(end 24.02713 -312.655458)
		(width 0.20066)
		(layer "F.Cu")
		(net "M_C_CPU1_SA_DQS_DP<0>")
	)
	(segment
		(start 31.876746 -312.91657)
		(end 30.771846 -312.91657)
		(width 0.20066)
		(layer "F.Cu")
		(net "M_C_CPU1_SA_DQS_DP<0>")
	)
	(segment
		(start 28.681172 -313.341766)
		(end 28.942284 -313.080654)
		(width 0.20066)
		(layer "F.Cu")
		(net "M_C_CPU1_SA_DQS_DP<0>")
	)
	(segment
		(start 24.02713 -312.655458)
		(end 24.452072 -312.655458)
		(width 0.20066)
		(layer "F.Cu")
		(net "M_C_CPU1_SA_DQS_DP<0>")
	)
	(segment
		(start 25.985724 -313.351164)
		(end 26.20391 -313.351164)
		(width 0.20066)
		(layer "F.Cu")
		(net "M_C_CPU1_SA_DQS_DP<0>")
	)
	(segment
		(start 29.693362 -312.655458)
		(end 29.962094 -312.655458)
		(width 0.20066)
		(layer "F.Cu")
		(net "M_C_CPU1_SA_DQS_DP<0>")
	)
	(segment
		(start 28.529026 -313.341766)
		(end 28.681172 -313.341766)
		(width 0.20066)
		(layer "F.Cu")
		(net "M_C_CPU1_SA_DQS_DP<0>")
	)
	(segment
		(start 30.223206 -312.91657)
		(end 30.771846 -312.91657)
		(width 0.20066)
		(layer "F.Cu")
		(net "M_C_CPU1_SA_DQS_DP<0>")
	)
	(segment
		(start 25.715214 -313.080654)
		(end 25.985724 -313.351164)
		(width 0.20066)
		(layer "F.Cu")
		(net "M_C_CPU1_SA_DQS_DP<0>")
	)
	(segment
		(start 26.20391 -313.351164)
		(end 26.213308 -313.341766)
		(width 0.101854)
		(layer "F.Cu")
		(net "M_C_CPU1_SA_DQS_DP<0>")
	)
	(segment
		(start 66.872866 -311.284112)
		(end 64.531748 -312.25363)
		(width 0.18288)
		(layer "In4.Cu")
		(net "M_C_CPU1_SA_DQS_DP<0>")
	)
	(segment
		(start 90.700098 -279.964134)
		(end 90.700098 -279.971754)
		(width 0.088646)
		(layer "In4.Cu")
		(net "M_C_CPU1_SA_DQS_DP<0>")
	)
	(segment
		(start 41.489376 -313.963812)
		(end 39.345362 -313.07532)
		(width 0.18288)
		(layer "In4.Cu")
		(net "M_C_CPU1_SA_DQS_DP<0>")
	)
	(segment
		(start 58.649616 -312.25363)
		(end 56.92521 -313.978036)
		(width 0.18288)
		(layer "In4.Cu")
		(net "M_C_CPU1_SA_DQS_DP<0>")
	)
	(segment
		(start 89.007696 -282.895548)
		(end 88.998806 -282.900628)
		(width 0.088646)
		(layer "In4.Cu")
		(net "M_C_CPU1_SA_DQS_DP<0>")
	)
	(segment
		(start 87.880444 -284.847538)
		(end 87.880444 -284.857444)
		(width 0.088646)
		(layer "In4.Cu")
		(net "M_C_CPU1_SA_DQS_DP<0>")
	)
	(segment
		(start 47.435262 -315.606938)
		(end 47.150274 -315.891926)
		(width 0.18288)
		(layer "In4.Cu")
		(net "M_C_CPU1_SA_DQS_DP<0>")
	)
	(segment
		(start 90.887296 -278.012144)
		(end 90.878406 -278.017224)
		(width 0.088646)
		(layer "In4.Cu")
		(net "M_C_CPU1_SA_DQS_DP<0>")
	)
	(segment
		(start 46.4947 -315.61532)
		(end 45.90542 -315.61532)
		(width 0.18288)
		(layer "In4.Cu")
		(net "M_C_CPU1_SA_DQS_DP<0>")
	)
	(segment
		(start 90.416634 -279.474168)
		(end 90.417396 -279.474676)
		(width 0.088646)
		(layer "In4.Cu")
		(net "M_C_CPU1_SA_DQS_DP<0>")
	)
	(segment
		(start 90.421206 -279.476962)
		(end 90.429588 -279.481788)
		(width 0.088646)
		(layer "In4.Cu")
		(net "M_C_CPU1_SA_DQS_DP<0>")
	)
	(segment
		(start 89.948258 -281.916886)
		(end 89.953592 -281.919934)
		(width 0.088646)
		(layer "In4.Cu")
		(net "M_C_CPU1_SA_DQS_DP<0>")
	)
	(segment
		(start 49.154842 -315.606938)
		(end 47.435262 -315.606938)
		(width 0.18288)
		(layer "In4.Cu")
		(net "M_C_CPU1_SA_DQS_DP<0>")
	)
	(segment
		(start 88.069166 -284.522418)
		(end 88.067896 -284.52318)
		(width 0.088646)
		(layer "In4.Cu")
		(net "M_C_CPU1_SA_DQS_DP<0>")
	)
	(segment
		(start 90.229944 -280.778204)
		(end 90.229944 -280.78811)
		(width 0.088646)
		(layer "In4.Cu")
		(net "M_C_CPU1_SA_DQS_DP<0>")
	)
	(segment
		(start 90.416634 -278.826468)
		(end 90.408506 -278.83104)
		(width 0.088646)
		(layer "In4.Cu")
		(net "M_C_CPU1_SA_DQS_DP<0>")
	)
	(segment
		(start 88.067896 -284.52318)
		(end 88.059006 -284.52826)
		(width 0.088646)
		(layer "In4.Cu")
		(net "M_C_CPU1_SA_DQS_DP<0>")
	)
	(segment
		(start 56.92521 -313.978036)
		(end 55.92445 -313.978036)
		(width 0.18288)
		(layer "In4.Cu")
		(net "M_C_CPU1_SA_DQS_DP<0>")
	)
	(segment
		(start 51.540664 -314.766198)
		(end 51.265074 -315.041788)
		(width 0.18288)
		(layer "In4.Cu")
		(net "M_C_CPU1_SA_DQS_DP<0>")
	)
	(segment
		(start 82.466434 -288.426398)
		(end 78.683612 -297.55719)
		(width 0.18288)
		(layer "In4.Cu")
		(net "M_C_CPU1_SA_DQS_DP<0>")
	)
	(segment
		(start 91.514168 -277.895812)
		(end 91.457018 -277.888954)
		(width 0.088646)
		(layer "In4.Cu")
		(net "M_C_CPU1_SA_DQS_DP<0>")
	)
	(segment
		(start 35.498024 -313.056524)
		(end 34.870898 -313.056524)
		(width 0.18288)
		(layer "In4.Cu")
		(net "M_C_CPU1_SA_DQS_DP<0>")
	)
	(segment
		(start 88.537034 -283.709872)
		(end 88.52916 -283.714444)
		(width 0.088646)
		(layer "In4.Cu")
		(net "M_C_CPU1_SA_DQS_DP<0>")
	)
	(segment
		(start 55.92445 -313.978036)
		(end 55.136288 -314.766198)
		(width 0.18288)
		(layer "In4.Cu")
		(net "M_C_CPU1_SA_DQS_DP<0>")
	)
	(segment
		(start 32.58566 -312.640726)
		(end 32.15259 -312.640726)
		(width 0.18288)
		(layer "In4.Cu")
		(net "M_C_CPU1_SA_DQS_DP<0>")
	)
	(segment
		(start 85.172804 -285.86303)
		(end 85.172804 -285.947866)
		(width 0.088646)
		(layer "In4.Cu")
		(net "M_C_CPU1_SA_DQS_DP<0>")
	)
	(segment
		(start 55.136288 -314.766198)
		(end 51.540664 -314.766198)
		(width 0.18288)
		(layer "In4.Cu")
		(net "M_C_CPU1_SA_DQS_DP<0>")
	)
	(segment
		(start 34.252916 -312.438542)
		(end 32.787844 -312.438542)
		(width 0.18288)
		(layer "In4.Cu")
		(net "M_C_CPU1_SA_DQS_DP<0>")
	)
	(segment
		(start 35.783266 -313.341766)
		(end 35.498024 -313.056524)
		(width 0.18288)
		(layer "In4.Cu")
		(net "M_C_CPU1_SA_DQS_DP<0>")
	)
	(segment
		(start 89.947496 -282.895548)
		(end 89.932764 -282.904184)
		(width 0.088646)
		(layer "In4.Cu")
		(net "M_C_CPU1_SA_DQS_DP<0>")
	)
	(segment
		(start 78.683612 -297.55719)
		(end 71.910702 -304.3301)
		(width 0.18288)
		(layer "In4.Cu")
		(net "M_C_CPU1_SA_DQS_DP<0>")
	)
	(segment
		(start 85.13826 -285.98241)
		(end 84.60867 -286.512)
		(width 0.18288)
		(layer "In4.Cu")
		(net "M_C_CPU1_SA_DQS_DP<0>")
	)
	(segment
		(start 32.787844 -312.438542)
		(end 32.58566 -312.640726)
		(width 0.18288)
		(layer "In4.Cu")
		(net "M_C_CPU1_SA_DQS_DP<0>")
	)
	(segment
		(start 50.012092 -314.749688)
		(end 49.154842 -315.606938)
		(width 0.18288)
		(layer "In4.Cu")
		(net "M_C_CPU1_SA_DQS_DP<0>")
	)
	(segment
		(start 64.531748 -312.25363)
		(end 58.649616 -312.25363)
		(width 0.18288)
		(layer "In4.Cu")
		(net "M_C_CPU1_SA_DQS_DP<0>")
	)
	(segment
		(start 90.417396 -280.453846)
		(end 90.408506 -280.458926)
		(width 0.088646)
		(layer "In4.Cu")
		(net "M_C_CPU1_SA_DQS_DP<0>")
	)
	(segment
		(start 92.143834 -277.612348)
		(end 91.718638 -277.854156)
		(width 0.088646)
		(layer "In4.Cu")
		(net "M_C_CPU1_SA_DQS_DP<0>")
	)
	(segment
		(start 91.452192 -277.891494)
		(end 91.402154 -277.891494)
		(width 0.088646)
		(layer "In4.Cu")
		(net "M_C_CPU1_SA_DQS_DP<0>")
	)
	(segment
		(start 90.417396 -279.474676)
		(end 90.421206 -279.476962)
		(width 0.088646)
		(layer "In4.Cu")
		(net "M_C_CPU1_SA_DQS_DP<0>")
	)
	(segment
		(start 32.15259 -312.640726)
		(end 31.876746 -312.91657)
		(width 0.18288)
		(layer "In4.Cu")
		(net "M_C_CPU1_SA_DQS_DP<0>")
	)
	(segment
		(start 50.579274 -314.749688)
		(end 50.012092 -314.749688)
		(width 0.18288)
		(layer "In4.Cu")
		(net "M_C_CPU1_SA_DQS_DP<0>")
	)
	(segment
		(start 85.642704 -285.3944)
		(end 85.172804 -285.86303)
		(width 0.088646)
		(layer "In4.Cu")
		(net "M_C_CPU1_SA_DQS_DP<0>")
	)
	(segment
		(start 36.173918 -313.341766)
		(end 35.783266 -313.341766)
		(width 0.18288)
		(layer "In4.Cu")
		(net "M_C_CPU1_SA_DQS_DP<0>")
	)
	(segment
		(start 88.53805 -283.709364)
		(end 88.537034 -283.709872)
		(width 0.088646)
		(layer "In4.Cu")
		(net "M_C_CPU1_SA_DQS_DP<0>")
	)
	(segment
		(start 34.870898 -313.056524)
		(end 34.252916 -312.438542)
		(width 0.18288)
		(layer "In4.Cu")
		(net "M_C_CPU1_SA_DQS_DP<0>")
	)
	(segment
		(start 84.60867 -286.512)
		(end 84.380578 -286.512)
		(width 0.18288)
		(layer "In4.Cu")
		(net "M_C_CPU1_SA_DQS_DP<0>")
	)
	(segment
		(start 92.484194 -277.522432)
		(end 92.361004 -277.522432)
		(width 0.088646)
		(layer "In4.Cu")
		(net "M_C_CPU1_SA_DQS_DP<0>")
	)
	(segment
		(start 88.080088 -284.516068)
		(end 88.069166 -284.522418)
		(width 0.088646)
		(layer "In4.Cu")
		(net "M_C_CPU1_SA_DQS_DP<0>")
	)
	(segment
		(start 89.947496 -281.916378)
		(end 89.948258 -281.916886)
		(width 0.088646)
		(layer "In4.Cu")
		(net "M_C_CPU1_SA_DQS_DP<0>")
	)
	(segment
		(start 71.910702 -306.246022)
		(end 66.872866 -311.284112)
		(width 0.18288)
		(layer "In4.Cu")
		(net "M_C_CPU1_SA_DQS_DP<0>")
	)
	(segment
		(start 39.345362 -313.07532)
		(end 36.440364 -313.07532)
		(width 0.18288)
		(layer "In4.Cu")
		(net "M_C_CPU1_SA_DQS_DP<0>")
	)
	(segment
		(start 46.771306 -315.891926)
		(end 46.4947 -315.61532)
		(width 0.18288)
		(layer "In4.Cu")
		(net "M_C_CPU1_SA_DQS_DP<0>")
	)
	(segment
		(start 47.150274 -315.891926)
		(end 46.771306 -315.891926)
		(width 0.18288)
		(layer "In4.Cu")
		(net "M_C_CPU1_SA_DQS_DP<0>")
	)
	(segment
		(start 90.699844 -278.336502)
		(end 90.699844 -278.346408)
		(width 0.088646)
		(layer "In4.Cu")
		(net "M_C_CPU1_SA_DQS_DP<0>")
	)
	(segment
		(start 36.440364 -313.07532)
		(end 36.173918 -313.341766)
		(width 0.18288)
		(layer "In4.Cu")
		(net "M_C_CPU1_SA_DQS_DP<0>")
	)
	(segment
		(start 43.795442 -313.963812)
		(end 41.489376 -313.963812)
		(width 0.18288)
		(layer "In4.Cu")
		(net "M_C_CPU1_SA_DQS_DP<0>")
	)
	(segment
		(start 45.374814 -315.084714)
		(end 44.59224 -314.760356)
		(width 0.18288)
		(layer "In4.Cu")
		(net "M_C_CPU1_SA_DQS_DP<0>")
	)
	(segment
		(start 51.265074 -315.041788)
		(end 50.871374 -315.041788)
		(width 0.18288)
		(layer "In4.Cu")
		(net "M_C_CPU1_SA_DQS_DP<0>")
	)
	(segment
		(start 45.90542 -315.61532)
		(end 45.374814 -315.084714)
		(width 0.18288)
		(layer "In4.Cu")
		(net "M_C_CPU1_SA_DQS_DP<0>")
	)
	(segment
		(start 90.230198 -282.405836)
		(end 90.230198 -282.42006)
		(width 0.088646)
		(layer "In4.Cu")
		(net "M_C_CPU1_SA_DQS_DP<0>")
	)
	(segment
		(start 90.408506 -279.469596)
		(end 90.416634 -279.474168)
		(width 0.088646)
		(layer "In4.Cu")
		(net "M_C_CPU1_SA_DQS_DP<0>")
	)
	(segment
		(start 85.172804 -285.947866)
		(end 85.13826 -285.98241)
		(width 0.088646)
		(layer "In4.Cu")
		(net "M_C_CPU1_SA_DQS_DP<0>")
	)
	(segment
		(start 88.820244 -283.219906)
		(end 88.820244 -283.2354)
		(width 0.088646)
		(layer "In4.Cu")
		(net "M_C_CPU1_SA_DQS_DP<0>")
	)
	(segment
		(start 50.871374 -315.041788)
		(end 50.579274 -314.749688)
		(width 0.18288)
		(layer "In4.Cu")
		(net "M_C_CPU1_SA_DQS_DP<0>")
	)
	(segment
		(start 90.417396 -278.82596)
		(end 90.416634 -278.826468)
		(width 0.088646)
		(layer "In4.Cu")
		(net "M_C_CPU1_SA_DQS_DP<0>")
	)
	(segment
		(start 71.910702 -304.3301)
		(end 71.910702 -306.246022)
		(width 0.18288)
		(layer "In4.Cu")
		(net "M_C_CPU1_SA_DQS_DP<0>")
	)
	(segment
		(start 44.59224 -314.760356)
		(end 43.795442 -313.963812)
		(width 0.18288)
		(layer "In4.Cu")
		(net "M_C_CPU1_SA_DQS_DP<0>")
	)
	(segment
		(start 84.380578 -286.512)
		(end 82.466434 -288.426398)
		(width 0.18288)
		(layer "In4.Cu")
		(net "M_C_CPU1_SA_DQS_DP<0>")
	)
	(segment
		(start 91.457018 -277.888954)
		(end 91.452192 -277.891494)
		(width 0.088646)
		(layer "In4.Cu")
		(net "M_C_CPU1_SA_DQS_DP<0>")
	)
	(arc
		(start 90.878406 -278.017224)
		(mid 90.747492 -278.153584)
		(end 90.699844 -278.336502)
		(width 0.088646)
		(layer "In4.Cu")
		(net "M_C_CPU1_SA_DQS_DP<0>")
	)
	(arc
		(start 89.953592 -281.919934)
		(mid 90.156179 -282.126285)
		(end 90.230198 -282.405836)
		(width 0.088646)
		(layer "In4.Cu")
		(net "M_C_CPU1_SA_DQS_DP<0>")
	)
	(arc
		(start 88.998806 -282.900628)
		(mid 88.867892 -283.036988)
		(end 88.820244 -283.219906)
		(width 0.088646)
		(layer "In4.Cu")
		(net "M_C_CPU1_SA_DQS_DP<0>")
	)
	(arc
		(start 90.230198 -282.42006)
		(mid 90.150979 -282.694745)
		(end 89.947496 -282.895548)
		(width 0.088646)
		(layer "In4.Cu")
		(net "M_C_CPU1_SA_DQS_DP<0>")
	)
	(arc
		(start 88.059006 -284.52826)
		(mid 87.928092 -284.66462)
		(end 87.880444 -284.847538)
		(width 0.088646)
		(layer "In4.Cu")
		(net "M_C_CPU1_SA_DQS_DP<0>")
	)
	(arc
		(start 89.947496 -281.267662)
		(mid 89.76032 -281.59202)
		(end 89.947496 -281.916378)
		(width 0.088646)
		(layer "In4.Cu")
		(net "M_C_CPU1_SA_DQS_DP<0>")
	)
	(arc
		(start 90.699844 -278.346408)
		(mid 90.621733 -278.623357)
		(end 90.417396 -278.82596)
		(width 0.088646)
		(layer "In4.Cu")
		(net "M_C_CPU1_SA_DQS_DP<0>")
	)
	(arc
		(start 91.718638 -277.854156)
		(mid 91.619796 -277.891666)
		(end 91.514168 -277.895812)
		(width 0.088646)
		(layer "In4.Cu")
		(net "M_C_CPU1_SA_DQS_DP<0>")
	)
	(arc
		(start 85.95741 -285.29026)
		(mid 85.833752 -285.293441)
		(end 85.717888 -285.336742)
		(width 0.088646)
		(layer "In4.Cu")
		(net "M_C_CPU1_SA_DQS_DP<0>")
	)
	(arc
		(start 89.932764 -282.904184)
		(mid 89.656323 -282.97135)
		(end 89.382092 -282.895548)
		(width 0.088646)
		(layer "In4.Cu")
		(net "M_C_CPU1_SA_DQS_DP<0>")
	)
	(arc
		(start 90.229944 -280.78811)
		(mid 90.151833 -281.065059)
		(end 89.947496 -281.267662)
		(width 0.088646)
		(layer "In4.Cu")
		(net "M_C_CPU1_SA_DQS_DP<0>")
	)
	(arc
		(start 90.429588 -279.481788)
		(mid 90.627816 -279.687636)
		(end 90.700098 -279.964134)
		(width 0.088646)
		(layer "In4.Cu")
		(net "M_C_CPU1_SA_DQS_DP<0>")
	)
	(arc
		(start 90.700098 -279.971754)
		(mid 90.622469 -280.250167)
		(end 90.417396 -280.453846)
		(width 0.088646)
		(layer "In4.Cu")
		(net "M_C_CPU1_SA_DQS_DP<0>")
	)
	(arc
		(start 92.361004 -277.522432)
		(mid 92.243487 -277.545808)
		(end 92.143834 -277.612348)
		(width 0.088646)
		(layer "In4.Cu")
		(net "M_C_CPU1_SA_DQS_DP<0>")
	)
	(arc
		(start 87.032592 -285.336996)
		(mid 86.845394 -285.286853)
		(end 86.658196 -285.336996)
		(width 0.088646)
		(layer "In4.Cu")
		(net "M_C_CPU1_SA_DQS_DP<0>")
	)
	(arc
		(start 89.382092 -282.895548)
		(mid 89.194894 -282.845405)
		(end 89.007696 -282.895548)
		(width 0.088646)
		(layer "In4.Cu")
		(net "M_C_CPU1_SA_DQS_DP<0>")
	)
	(arc
		(start 91.402154 -277.891494)
		(mid 91.326755 -277.905185)
		(end 91.250262 -277.909782)
		(width 0.088646)
		(layer "In4.Cu")
		(net "M_C_CPU1_SA_DQS_DP<0>")
	)
	(arc
		(start 87.880444 -284.857444)
		(mid 87.802333 -285.134393)
		(end 87.597996 -285.336996)
		(width 0.088646)
		(layer "In4.Cu")
		(net "M_C_CPU1_SA_DQS_DP<0>")
	)
	(arc
		(start 85.717888 -285.336742)
		(mid 85.678406 -285.363107)
		(end 85.642704 -285.3944)
		(width 0.088646)
		(layer "In4.Cu")
		(net "M_C_CPU1_SA_DQS_DP<0>")
	)
	(arc
		(start 90.408506 -278.83104)
		(mid 90.229909 -279.150318)
		(end 90.408506 -279.469596)
		(width 0.088646)
		(layer "In4.Cu")
		(net "M_C_CPU1_SA_DQS_DP<0>")
	)
	(arc
		(start 88.52916 -283.714444)
		(mid 88.398246 -283.850804)
		(end 88.350598 -284.033722)
		(width 0.088646)
		(layer "In4.Cu")
		(net "M_C_CPU1_SA_DQS_DP<0>")
	)
	(arc
		(start 86.658196 -285.336996)
		(mid 86.375719 -285.412518)
		(end 86.0933 -285.336742)
		(width 0.088646)
		(layer "In4.Cu")
		(net "M_C_CPU1_SA_DQS_DP<0>")
	)
	(arc
		(start 86.0933 -285.336742)
		(mid 86.027599 -285.306945)
		(end 85.95741 -285.29026)
		(width 0.088646)
		(layer "In4.Cu")
		(net "M_C_CPU1_SA_DQS_DP<0>")
	)
	(arc
		(start 91.250262 -277.909782)
		(mid 91.0617 -277.935862)
		(end 90.887296 -278.012144)
		(width 0.088646)
		(layer "In4.Cu")
		(net "M_C_CPU1_SA_DQS_DP<0>")
	)
	(arc
		(start 87.597996 -285.336996)
		(mid 87.315294 -285.412772)
		(end 87.032592 -285.336996)
		(width 0.088646)
		(layer "In4.Cu")
		(net "M_C_CPU1_SA_DQS_DP<0>")
	)
	(arc
		(start 90.408506 -280.458926)
		(mid 90.277592 -280.595286)
		(end 90.229944 -280.778204)
		(width 0.088646)
		(layer "In4.Cu")
		(net "M_C_CPU1_SA_DQS_DP<0>")
	)
	(arc
		(start 88.820244 -283.2354)
		(mid 88.740874 -283.509134)
		(end 88.53805 -283.709364)
		(width 0.088646)
		(layer "In4.Cu")
		(net "M_C_CPU1_SA_DQS_DP<0>")
	)
	(arc
		(start 88.350598 -284.033722)
		(mid 88.278363 -284.310246)
		(end 88.080088 -284.516068)
		(width 0.088646)
		(layer "In4.Cu")
		(net "M_C_CPU1_SA_DQS_DP<0>")
	)
	(segment
		(start 29.463492 -274.241768)
		(end 29.516324 -274.241768)
		(width 0.20066)
		(layer "F.Cu")
		(net "M_C_CPU1_SA_DQS_DN<9>")
	)
	(segment
		(start 31.972758 -274.241768)
		(end 32.025082 -274.241768)
		(width 0.101854)
		(layer "F.Cu")
		(net "M_C_CPU1_SA_DQS_DN<9>")
	)
	(segment
		(start 27.799792 -274.66671)
		(end 28.060904 -274.405598)
		(width 0.20066)
		(layer "F.Cu")
		(net "M_C_CPU1_SA_DQS_DN<9>")
	)
	(segment
		(start 97.653094 -259.894832)
		(end 97.653348 -260.430772)
		(width 0.20066)
		(layer "F.Cu")
		(net "M_C_CPU1_SA_DQS_DN<9>")
	)
	(segment
		(start 29.895292 -274.241768)
		(end 31.972758 -274.241768)
		(width 0.1016)
		(layer "F.Cu")
		(net "M_C_CPU1_SA_DQS_DN<9>")
	)
	(segment
		(start 34.38144 -274.66671)
		(end 34.871914 -274.66671)
		(width 0.20066)
		(layer "F.Cu")
		(net "M_C_CPU1_SA_DQS_DN<9>")
	)
	(segment
		(start 33.416748 -274.405598)
		(end 34.120328 -274.405598)
		(width 0.20066)
		(layer "F.Cu")
		(net "M_C_CPU1_SA_DQS_DN<9>")
	)
	(segment
		(start 32.025082 -274.241768)
		(end 32.114998 -274.241768)
		(width 0.20066)
		(layer "F.Cu")
		(net "M_C_CPU1_SA_DQS_DN<9>")
	)
	(segment
		(start 32.37611 -273.980656)
		(end 32.780732 -273.980656)
		(width 0.20066)
		(layer "F.Cu")
		(net "M_C_CPU1_SA_DQS_DN<9>")
	)
	(segment
		(start 32.114998 -274.241768)
		(end 32.37611 -273.980656)
		(width 0.20066)
		(layer "F.Cu")
		(net "M_C_CPU1_SA_DQS_DN<9>")
	)
	(segment
		(start 27.328114 -274.66671)
		(end 27.799792 -274.66671)
		(width 0.20066)
		(layer "F.Cu")
		(net "M_C_CPU1_SA_DQS_DN<9>")
	)
	(segment
		(start 28.534106 -274.405598)
		(end 28.953714 -273.98599)
		(width 0.20066)
		(layer "F.Cu")
		(net "M_C_CPU1_SA_DQS_DN<9>")
	)
	(segment
		(start 29.207714 -273.98599)
		(end 29.463492 -274.241768)
		(width 0.20066)
		(layer "F.Cu")
		(net "M_C_CPU1_SA_DQS_DN<9>")
	)
	(segment
		(start 28.953714 -273.98599)
		(end 29.207714 -273.98599)
		(width 0.20066)
		(layer "F.Cu")
		(net "M_C_CPU1_SA_DQS_DN<9>")
	)
	(segment
		(start 29.516324 -274.241768)
		(end 29.895292 -274.241768)
		(width 0.101854)
		(layer "F.Cu")
		(net "M_C_CPU1_SA_DQS_DN<9>")
	)
	(segment
		(start 32.780732 -273.980656)
		(end 33.416748 -274.405598)
		(width 0.20066)
		(layer "F.Cu")
		(net "M_C_CPU1_SA_DQS_DN<9>")
	)
	(segment
		(start 35.976814 -274.66671)
		(end 34.871914 -274.66671)
		(width 0.20066)
		(layer "F.Cu")
		(net "M_C_CPU1_SA_DQS_DN<9>")
	)
	(segment
		(start 28.060904 -274.405598)
		(end 28.534106 -274.405598)
		(width 0.20066)
		(layer "F.Cu")
		(net "M_C_CPU1_SA_DQS_DN<9>")
	)
	(segment
		(start 34.120328 -274.405598)
		(end 34.38144 -274.66671)
		(width 0.20066)
		(layer "F.Cu")
		(net "M_C_CPU1_SA_DQS_DN<9>")
	)
	(segment
		(start 81.47685 -261.897622)
		(end 78.33614 -263.198864)
		(width 0.18288)
		(layer "In6.Cu")
		(net "M_C_CPU1_SA_DQS_DN<9>")
	)
	(segment
		(start 83.939634 -260.995414)
		(end 83.09737 -261.837678)
		(width 0.088646)
		(layer "In6.Cu")
		(net "M_C_CPU1_SA_DQS_DN<9>")
	)
	(segment
		(start 49.360582 -268.57198)
		(end 48.860456 -268.77899)
		(width 0.18288)
		(layer "In6.Cu")
		(net "M_C_CPU1_SA_DQS_DN<9>")
	)
	(segment
		(start 48.860456 -268.77899)
		(end 48.33874 -269.300706)
		(width 0.18288)
		(layer "In6.Cu")
		(net "M_C_CPU1_SA_DQS_DN<9>")
	)
	(segment
		(start 47.934372 -270.555212)
		(end 47.518828 -270.555212)
		(width 0.18288)
		(layer "In6.Cu")
		(net "M_C_CPU1_SA_DQS_DN<9>")
	)
	(segment
		(start 36.254436 -274.389088)
		(end 35.976814 -274.66671)
		(width 0.18288)
		(layer "In6.Cu")
		(net "M_C_CPU1_SA_DQS_DN<9>")
	)
	(segment
		(start 71.853298 -263.198864)
		(end 65.33642 -265.89863)
		(width 0.18288)
		(layer "In6.Cu")
		(net "M_C_CPU1_SA_DQS_DN<9>")
	)
	(segment
		(start 37.504878 -274.586954)
		(end 36.893754 -274.586954)
		(width 0.18288)
		(layer "In6.Cu")
		(net "M_C_CPU1_SA_DQS_DN<9>")
	)
	(segment
		(start 43.042078 -270.878046)
		(end 41.866312 -272.053558)
		(width 0.18288)
		(layer "In6.Cu")
		(net "M_C_CPU1_SA_DQS_DN<9>")
	)
	(segment
		(start 82.741262 -261.837678)
		(end 82.681318 -261.897622)
		(width 0.088646)
		(layer "In6.Cu")
		(net "M_C_CPU1_SA_DQS_DN<9>")
	)
	(segment
		(start 96.445324 -260.92912)
		(end 96.430592 -260.920484)
		(width 0.088646)
		(layer "In6.Cu")
		(net "M_C_CPU1_SA_DQS_DN<9>")
	)
	(segment
		(start 44.307506 -269.96898)
		(end 43.650662 -270.625824)
		(width 0.18288)
		(layer "In6.Cu")
		(net "M_C_CPU1_SA_DQS_DN<9>")
	)
	(segment
		(start 82.681318 -261.897622)
		(end 82.65795 -261.897622)
		(width 0.088646)
		(layer "In6.Cu")
		(net "M_C_CPU1_SA_DQS_DN<9>")
	)
	(segment
		(start 61.913008 -266.536424)
		(end 61.452506 -266.727178)
		(width 0.18288)
		(layer "In6.Cu")
		(net "M_C_CPU1_SA_DQS_DN<9>")
	)
	(segment
		(start 51.611022 -268.012926)
		(end 51.321462 -268.302486)
		(width 0.18288)
		(layer "In6.Cu")
		(net "M_C_CPU1_SA_DQS_DN<9>")
	)
	(segment
		(start 64.27597 -266.958826)
		(end 63.377826 -266.958826)
		(width 0.18288)
		(layer "In6.Cu")
		(net "M_C_CPU1_SA_DQS_DN<9>")
	)
	(segment
		(start 51.321462 -268.302486)
		(end 50.886106 -268.302486)
		(width 0.18288)
		(layer "In6.Cu")
		(net "M_C_CPU1_SA_DQS_DN<9>")
	)
	(segment
		(start 43.650662 -270.625824)
		(end 43.042078 -270.878046)
		(width 0.18288)
		(layer "In6.Cu")
		(net "M_C_CPU1_SA_DQS_DN<9>")
	)
	(segment
		(start 38.745668 -273.346164)
		(end 37.504878 -274.586954)
		(width 0.18288)
		(layer "In6.Cu")
		(net "M_C_CPU1_SA_DQS_DN<9>")
	)
	(segment
		(start 45.833284 -270.557244)
		(end 45.24502 -269.96898)
		(width 0.18288)
		(layer "In6.Cu")
		(net "M_C_CPU1_SA_DQS_DN<9>")
	)
	(segment
		(start 97.340166 -260.430772)
		(end 97.274888 -260.49605)
		(width 0.088646)
		(layer "In6.Cu")
		(net "M_C_CPU1_SA_DQS_DN<9>")
	)
	(segment
		(start 50.886106 -268.302486)
		(end 50.590704 -268.007084)
		(width 0.18288)
		(layer "In6.Cu")
		(net "M_C_CPU1_SA_DQS_DN<9>")
	)
	(segment
		(start 63.377826 -266.958826)
		(end 62.357762 -266.536424)
		(width 0.18288)
		(layer "In6.Cu")
		(net "M_C_CPU1_SA_DQS_DN<9>")
	)
	(segment
		(start 83.09737 -261.837678)
		(end 82.741262 -261.837678)
		(width 0.088646)
		(layer "In6.Cu")
		(net "M_C_CPU1_SA_DQS_DN<9>")
	)
	(segment
		(start 91.357196 -260.920484)
		(end 91.342464 -260.92912)
		(width 0.088646)
		(layer "In6.Cu")
		(net "M_C_CPU1_SA_DQS_DN<9>")
	)
	(segment
		(start 93.236796 -260.920484)
		(end 93.222064 -260.92912)
		(width 0.088646)
		(layer "In6.Cu")
		(net "M_C_CPU1_SA_DQS_DN<9>")
	)
	(segment
		(start 36.695888 -274.389088)
		(end 36.254436 -274.389088)
		(width 0.18288)
		(layer "In6.Cu")
		(net "M_C_CPU1_SA_DQS_DN<9>")
	)
	(segment
		(start 46.775624 -270.842232)
		(end 46.490636 -270.557244)
		(width 0.18288)
		(layer "In6.Cu")
		(net "M_C_CPU1_SA_DQS_DN<9>")
	)
	(segment
		(start 48.33874 -270.150844)
		(end 47.934372 -270.555212)
		(width 0.18288)
		(layer "In6.Cu")
		(net "M_C_CPU1_SA_DQS_DN<9>")
	)
	(segment
		(start 45.24502 -269.96898)
		(end 44.307506 -269.96898)
		(width 0.18288)
		(layer "In6.Cu")
		(net "M_C_CPU1_SA_DQS_DN<9>")
	)
	(segment
		(start 61.452506 -266.727178)
		(end 60.408058 -267.771626)
		(width 0.18288)
		(layer "In6.Cu")
		(net "M_C_CPU1_SA_DQS_DN<9>")
	)
	(segment
		(start 90.417396 -260.920484)
		(end 90.402664 -260.92912)
		(width 0.088646)
		(layer "In6.Cu")
		(net "M_C_CPU1_SA_DQS_DN<9>")
	)
	(segment
		(start 49.925224 -268.007084)
		(end 49.360582 -268.57198)
		(width 0.18288)
		(layer "In6.Cu")
		(net "M_C_CPU1_SA_DQS_DN<9>")
	)
	(segment
		(start 78.33614 -263.198864)
		(end 71.853298 -263.198864)
		(width 0.18288)
		(layer "In6.Cu")
		(net "M_C_CPU1_SA_DQS_DN<9>")
	)
	(segment
		(start 59.671712 -267.771626)
		(end 58.471562 -267.274548)
		(width 0.18288)
		(layer "In6.Cu")
		(net "M_C_CPU1_SA_DQS_DN<9>")
	)
	(segment
		(start 94.176596 -260.920484)
		(end 94.161864 -260.92912)
		(width 0.088646)
		(layer "In6.Cu")
		(net "M_C_CPU1_SA_DQS_DN<9>")
	)
	(segment
		(start 36.893754 -274.586954)
		(end 36.695888 -274.389088)
		(width 0.18288)
		(layer "In6.Cu")
		(net "M_C_CPU1_SA_DQS_DN<9>")
	)
	(segment
		(start 54.63794 -268.012926)
		(end 51.611022 -268.012926)
		(width 0.18288)
		(layer "In6.Cu")
		(net "M_C_CPU1_SA_DQS_DN<9>")
	)
	(segment
		(start 41.866312 -272.053558)
		(end 38.745668 -273.346164)
		(width 0.18288)
		(layer "In6.Cu")
		(net "M_C_CPU1_SA_DQS_DN<9>")
	)
	(segment
		(start 58.471562 -267.274548)
		(end 56.421782 -267.274548)
		(width 0.18288)
		(layer "In6.Cu")
		(net "M_C_CPU1_SA_DQS_DN<9>")
	)
	(segment
		(start 47.518828 -270.555212)
		(end 47.231808 -270.842232)
		(width 0.18288)
		(layer "In6.Cu")
		(net "M_C_CPU1_SA_DQS_DN<9>")
	)
	(segment
		(start 62.357762 -266.536424)
		(end 61.913008 -266.536424)
		(width 0.18288)
		(layer "In6.Cu")
		(net "M_C_CPU1_SA_DQS_DN<9>")
	)
	(segment
		(start 82.65795 -261.897622)
		(end 81.47685 -261.897622)
		(width 0.18288)
		(layer "In6.Cu")
		(net "M_C_CPU1_SA_DQS_DN<9>")
	)
	(segment
		(start 50.590704 -268.007084)
		(end 49.925224 -268.007084)
		(width 0.18288)
		(layer "In6.Cu")
		(net "M_C_CPU1_SA_DQS_DN<9>")
	)
	(segment
		(start 89.477596 -260.920484)
		(end 89.462864 -260.92912)
		(width 0.088646)
		(layer "In6.Cu")
		(net "M_C_CPU1_SA_DQS_DN<9>")
	)
	(segment
		(start 65.33642 -265.89863)
		(end 64.27597 -266.958826)
		(width 0.18288)
		(layer "In6.Cu")
		(net "M_C_CPU1_SA_DQS_DN<9>")
	)
	(segment
		(start 60.408058 -267.771626)
		(end 59.671712 -267.771626)
		(width 0.18288)
		(layer "In6.Cu")
		(net "M_C_CPU1_SA_DQS_DN<9>")
	)
	(segment
		(start 94.565724 -260.92912)
		(end 94.550992 -260.920484)
		(width 0.088646)
		(layer "In6.Cu")
		(net "M_C_CPU1_SA_DQS_DN<9>")
	)
	(segment
		(start 96.056196 -260.920484)
		(end 96.041464 -260.92912)
		(width 0.088646)
		(layer "In6.Cu")
		(net "M_C_CPU1_SA_DQS_DN<9>")
	)
	(segment
		(start 47.231808 -270.842232)
		(end 46.775624 -270.842232)
		(width 0.18288)
		(layer "In6.Cu")
		(net "M_C_CPU1_SA_DQS_DN<9>")
	)
	(segment
		(start 46.490636 -270.557244)
		(end 45.833284 -270.557244)
		(width 0.18288)
		(layer "In6.Cu")
		(net "M_C_CPU1_SA_DQS_DN<9>")
	)
	(segment
		(start 56.421782 -267.274548)
		(end 54.63794 -268.012926)
		(width 0.18288)
		(layer "In6.Cu")
		(net "M_C_CPU1_SA_DQS_DN<9>")
	)
	(segment
		(start 48.33874 -269.300706)
		(end 48.33874 -270.150844)
		(width 0.18288)
		(layer "In6.Cu")
		(net "M_C_CPU1_SA_DQS_DN<9>")
	)
	(segment
		(start 97.653348 -260.430772)
		(end 97.340166 -260.430772)
		(width 0.088646)
		(layer "In6.Cu")
		(net "M_C_CPU1_SA_DQS_DN<9>")
	)
	(arc
		(start 96.041464 -260.92912)
		(mid 95.765023 -260.996286)
		(end 95.490792 -260.920484)
		(width 0.088646)
		(layer "In6.Cu")
		(net "M_C_CPU1_SA_DQS_DN<9>")
	)
	(arc
		(start 87.032592 -260.920484)
		(mid 86.845394 -260.870341)
		(end 86.658196 -260.920484)
		(width 0.088646)
		(layer "In6.Cu")
		(net "M_C_CPU1_SA_DQS_DN<9>")
	)
	(arc
		(start 90.402664 -260.92912)
		(mid 90.126223 -260.996286)
		(end 89.851992 -260.920484)
		(width 0.088646)
		(layer "In6.Cu")
		(net "M_C_CPU1_SA_DQS_DN<9>")
	)
	(arc
		(start 95.116396 -260.920484)
		(mid 94.842167 -260.996409)
		(end 94.565724 -260.92912)
		(width 0.088646)
		(layer "In6.Cu")
		(net "M_C_CPU1_SA_DQS_DN<9>")
	)
	(arc
		(start 93.611192 -260.920484)
		(mid 93.423994 -260.870341)
		(end 93.236796 -260.920484)
		(width 0.088646)
		(layer "In6.Cu")
		(net "M_C_CPU1_SA_DQS_DN<9>")
	)
	(arc
		(start 85.718396 -260.920484)
		(mid 85.435694 -260.996226)
		(end 85.152992 -260.920484)
		(width 0.088646)
		(layer "In6.Cu")
		(net "M_C_CPU1_SA_DQS_DN<9>")
	)
	(arc
		(start 92.296996 -260.920484)
		(mid 92.014294 -260.996226)
		(end 91.731592 -260.920484)
		(width 0.088646)
		(layer "In6.Cu")
		(net "M_C_CPU1_SA_DQS_DN<9>")
	)
	(arc
		(start 97.274888 -260.49605)
		(mid 97.27359 -260.506604)
		(end 97.272094 -260.517132)
		(width 0.088646)
		(layer "In6.Cu")
		(net "M_C_CPU1_SA_DQS_DN<9>")
	)
	(arc
		(start 94.161864 -260.92912)
		(mid 93.885423 -260.996286)
		(end 93.611192 -260.920484)
		(width 0.088646)
		(layer "In6.Cu")
		(net "M_C_CPU1_SA_DQS_DN<9>")
	)
	(arc
		(start 84.778596 -260.920484)
		(mid 84.553398 -260.993396)
		(end 84.318094 -260.967728)
		(width 0.088646)
		(layer "In6.Cu")
		(net "M_C_CPU1_SA_DQS_DN<9>")
	)
	(arc
		(start 89.851992 -260.920484)
		(mid 89.664794 -260.870341)
		(end 89.477596 -260.920484)
		(width 0.088646)
		(layer "In6.Cu")
		(net "M_C_CPU1_SA_DQS_DN<9>")
	)
	(arc
		(start 88.912192 -260.920484)
		(mid 88.724994 -260.870341)
		(end 88.537796 -260.920484)
		(width 0.088646)
		(layer "In6.Cu")
		(net "M_C_CPU1_SA_DQS_DN<9>")
	)
	(arc
		(start 97.272094 -260.517132)
		(mid 97.1799 -260.750211)
		(end 96.995996 -260.920484)
		(width 0.088646)
		(layer "In6.Cu")
		(net "M_C_CPU1_SA_DQS_DN<9>")
	)
	(arc
		(start 84.318094 -260.967728)
		(mid 84.168757 -260.939693)
		(end 84.017358 -260.952488)
		(width 0.088646)
		(layer "In6.Cu")
		(net "M_C_CPU1_SA_DQS_DN<9>")
	)
	(arc
		(start 91.731592 -260.920484)
		(mid 91.544394 -260.870341)
		(end 91.357196 -260.920484)
		(width 0.088646)
		(layer "In6.Cu")
		(net "M_C_CPU1_SA_DQS_DN<9>")
	)
	(arc
		(start 87.597996 -260.920484)
		(mid 87.315294 -260.996226)
		(end 87.032592 -260.920484)
		(width 0.088646)
		(layer "In6.Cu")
		(net "M_C_CPU1_SA_DQS_DN<9>")
	)
	(arc
		(start 95.490792 -260.920484)
		(mid 95.303594 -260.870341)
		(end 95.116396 -260.920484)
		(width 0.088646)
		(layer "In6.Cu")
		(net "M_C_CPU1_SA_DQS_DN<9>")
	)
	(arc
		(start 96.995996 -260.920484)
		(mid 96.721767 -260.996409)
		(end 96.445324 -260.92912)
		(width 0.088646)
		(layer "In6.Cu")
		(net "M_C_CPU1_SA_DQS_DN<9>")
	)
	(arc
		(start 89.462864 -260.92912)
		(mid 89.186423 -260.996286)
		(end 88.912192 -260.920484)
		(width 0.088646)
		(layer "In6.Cu")
		(net "M_C_CPU1_SA_DQS_DN<9>")
	)
	(arc
		(start 93.222064 -260.92912)
		(mid 92.945623 -260.996286)
		(end 92.671392 -260.920484)
		(width 0.088646)
		(layer "In6.Cu")
		(net "M_C_CPU1_SA_DQS_DN<9>")
	)
	(arc
		(start 85.152992 -260.920484)
		(mid 84.965794 -260.870341)
		(end 84.778596 -260.920484)
		(width 0.088646)
		(layer "In6.Cu")
		(net "M_C_CPU1_SA_DQS_DN<9>")
	)
	(arc
		(start 87.972392 -260.920484)
		(mid 87.785194 -260.870341)
		(end 87.597996 -260.920484)
		(width 0.088646)
		(layer "In6.Cu")
		(net "M_C_CPU1_SA_DQS_DN<9>")
	)
	(arc
		(start 86.092792 -260.920484)
		(mid 85.905594 -260.870341)
		(end 85.718396 -260.920484)
		(width 0.088646)
		(layer "In6.Cu")
		(net "M_C_CPU1_SA_DQS_DN<9>")
	)
	(arc
		(start 88.537796 -260.920484)
		(mid 88.255094 -260.996226)
		(end 87.972392 -260.920484)
		(width 0.088646)
		(layer "In6.Cu")
		(net "M_C_CPU1_SA_DQS_DN<9>")
	)
	(arc
		(start 92.671392 -260.920484)
		(mid 92.484194 -260.870341)
		(end 92.296996 -260.920484)
		(width 0.088646)
		(layer "In6.Cu")
		(net "M_C_CPU1_SA_DQS_DN<9>")
	)
	(arc
		(start 96.430592 -260.920484)
		(mid 96.243394 -260.870341)
		(end 96.056196 -260.920484)
		(width 0.088646)
		(layer "In6.Cu")
		(net "M_C_CPU1_SA_DQS_DN<9>")
	)
	(arc
		(start 91.342464 -260.92912)
		(mid 91.066023 -260.996286)
		(end 90.791792 -260.920484)
		(width 0.088646)
		(layer "In6.Cu")
		(net "M_C_CPU1_SA_DQS_DN<9>")
	)
	(arc
		(start 94.550992 -260.920484)
		(mid 94.363794 -260.870341)
		(end 94.176596 -260.920484)
		(width 0.088646)
		(layer "In6.Cu")
		(net "M_C_CPU1_SA_DQS_DN<9>")
	)
	(arc
		(start 90.791792 -260.920484)
		(mid 90.604594 -260.870341)
		(end 90.417396 -260.920484)
		(width 0.088646)
		(layer "In6.Cu")
		(net "M_C_CPU1_SA_DQS_DN<9>")
	)
	(arc
		(start 84.017358 -260.952488)
		(mid 83.975443 -260.968416)
		(end 83.939634 -260.995414)
		(width 0.088646)
		(layer "In6.Cu")
		(net "M_C_CPU1_SA_DQS_DN<9>")
	)
	(arc
		(start 86.658196 -260.920484)
		(mid 86.375494 -260.996226)
		(end 86.092792 -260.920484)
		(width 0.088646)
		(layer "In6.Cu")
		(net "M_C_CPU1_SA_DQS_DN<9>")
	)
	(segment
		(start 96.713294 -264.778236)
		(end 96.713548 -265.314176)
		(width 0.20066)
		(layer "F.Cu")
		(net "M_C_CPU1_SA_DQS_DN<8>")
	)
	(segment
		(start 28.956508 -283.33319)
		(end 29.196284 -283.33319)
		(width 0.20066)
		(layer "F.Cu")
		(net "M_C_CPU1_SA_DQS_DN<8>")
	)
	(segment
		(start 29.647642 -283.601414)
		(end 29.657294 -283.591762)
		(width 0.101854)
		(layer "F.Cu")
		(net "M_C_CPU1_SA_DQS_DN<8>")
	)
	(segment
		(start 32.114998 -283.591762)
		(end 32.37611 -283.33065)
		(width 0.20066)
		(layer "F.Cu")
		(net "M_C_CPU1_SA_DQS_DN<8>")
	)
	(segment
		(start 31.972758 -283.591762)
		(end 32.114998 -283.591762)
		(width 0.20066)
		(layer "F.Cu")
		(net "M_C_CPU1_SA_DQS_DN<8>")
	)
	(segment
		(start 35.976814 -284.016704)
		(end 34.871914 -284.016704)
		(width 0.20066)
		(layer "F.Cu")
		(net "M_C_CPU1_SA_DQS_DN<8>")
	)
	(segment
		(start 29.196284 -283.33319)
		(end 29.464508 -283.601414)
		(width 0.20066)
		(layer "F.Cu")
		(net "M_C_CPU1_SA_DQS_DN<8>")
	)
	(segment
		(start 27.799792 -284.016704)
		(end 28.060904 -283.755592)
		(width 0.20066)
		(layer "F.Cu")
		(net "M_C_CPU1_SA_DQS_DN<8>")
	)
	(segment
		(start 32.780732 -283.33065)
		(end 33.416748 -283.755592)
		(width 0.20066)
		(layer "F.Cu")
		(net "M_C_CPU1_SA_DQS_DN<8>")
	)
	(segment
		(start 29.464508 -283.601414)
		(end 29.647642 -283.601414)
		(width 0.20066)
		(layer "F.Cu")
		(net "M_C_CPU1_SA_DQS_DN<8>")
	)
	(segment
		(start 27.328114 -284.016704)
		(end 27.799792 -284.016704)
		(width 0.20066)
		(layer "F.Cu")
		(net "M_C_CPU1_SA_DQS_DN<8>")
	)
	(segment
		(start 28.534106 -283.755592)
		(end 28.956508 -283.33319)
		(width 0.20066)
		(layer "F.Cu")
		(net "M_C_CPU1_SA_DQS_DN<8>")
	)
	(segment
		(start 33.416748 -283.755592)
		(end 34.120328 -283.755592)
		(width 0.20066)
		(layer "F.Cu")
		(net "M_C_CPU1_SA_DQS_DN<8>")
	)
	(segment
		(start 28.060904 -283.755592)
		(end 28.534106 -283.755592)
		(width 0.20066)
		(layer "F.Cu")
		(net "M_C_CPU1_SA_DQS_DN<8>")
	)
	(segment
		(start 29.895292 -283.591762)
		(end 31.972758 -283.591762)
		(width 0.1016)
		(layer "F.Cu")
		(net "M_C_CPU1_SA_DQS_DN<8>")
	)
	(segment
		(start 29.657294 -283.591762)
		(end 29.895292 -283.591762)
		(width 0.101854)
		(layer "F.Cu")
		(net "M_C_CPU1_SA_DQS_DN<8>")
	)
	(segment
		(start 34.120328 -283.755592)
		(end 34.38144 -284.016704)
		(width 0.20066)
		(layer "F.Cu")
		(net "M_C_CPU1_SA_DQS_DN<8>")
	)
	(segment
		(start 32.37611 -283.33065)
		(end 32.780732 -283.33065)
		(width 0.20066)
		(layer "F.Cu")
		(net "M_C_CPU1_SA_DQS_DN<8>")
	)
	(segment
		(start 34.38144 -284.016704)
		(end 34.871914 -284.016704)
		(width 0.20066)
		(layer "F.Cu")
		(net "M_C_CPU1_SA_DQS_DN<8>")
	)
	(segment
		(start 36.616132 -283.737558)
		(end 36.25596 -283.737558)
		(width 0.18288)
		(layer "In6.Cu")
		(net "M_C_CPU1_SA_DQS_DN<8>")
	)
	(segment
		(start 85.061044 -265.314176)
		(end 85.061044 -265.324082)
		(width 0.088646)
		(layer "In6.Cu")
		(net "M_C_CPU1_SA_DQS_DN<8>")
	)
	(segment
		(start 95.975678 -264.998454)
		(end 95.960946 -264.989818)
		(width 0.088646)
		(layer "In6.Cu")
		(net "M_C_CPU1_SA_DQS_DN<8>")
	)
	(segment
		(start 93.156278 -264.998454)
		(end 93.141546 -264.989818)
		(width 0.088646)
		(layer "In6.Cu")
		(net "M_C_CPU1_SA_DQS_DN<8>")
	)
	(segment
		(start 90.332306 -264.995914)
		(end 90.321892 -264.989818)
		(width 0.088646)
		(layer "In6.Cu")
		(net "M_C_CPU1_SA_DQS_DN<8>")
	)
	(segment
		(start 70.951344 -271.547082)
		(end 67.73545 -274.762976)
		(width 0.18288)
		(layer "In6.Cu")
		(net "M_C_CPU1_SA_DQS_DN<8>")
	)
	(segment
		(start 57.614312 -276.617684)
		(end 57.065672 -276.617684)
		(width 0.18288)
		(layer "In6.Cu")
		(net "M_C_CPU1_SA_DQS_DN<8>")
	)
	(segment
		(start 63.29045 -276.280626)
		(end 62.873382 -275.863558)
		(width 0.18288)
		(layer "In6.Cu")
		(net "M_C_CPU1_SA_DQS_DN<8>")
	)
	(segment
		(start 54.936644 -277.550372)
		(end 54.157118 -277.550372)
		(width 0.18288)
		(layer "In6.Cu")
		(net "M_C_CPU1_SA_DQS_DN<8>")
	)
	(segment
		(start 65.766442 -274.762976)
		(end 64.248792 -276.280626)
		(width 0.18288)
		(layer "In6.Cu")
		(net "M_C_CPU1_SA_DQS_DN<8>")
	)
	(segment
		(start 52.622704 -279.084786)
		(end 51.601624 -279.084786)
		(width 0.18288)
		(layer "In6.Cu")
		(net "M_C_CPU1_SA_DQS_DN<8>")
	)
	(segment
		(start 56.941212 -276.493224)
		(end 55.993792 -276.493224)
		(width 0.18288)
		(layer "In6.Cu")
		(net "M_C_CPU1_SA_DQS_DN<8>")
	)
	(segment
		(start 58.72734 -276.493224)
		(end 57.738772 -276.493224)
		(width 0.18288)
		(layer "In6.Cu")
		(net "M_C_CPU1_SA_DQS_DN<8>")
	)
	(segment
		(start 46.475396 -279.900888)
		(end 45.699426 -279.900888)
		(width 0.18288)
		(layer "In6.Cu")
		(net "M_C_CPU1_SA_DQS_DN<8>")
	)
	(segment
		(start 83.122516 -267.085826)
		(end 83.062572 -267.14577)
		(width 0.088646)
		(layer "In6.Cu")
		(net "M_C_CPU1_SA_DQS_DN<8>")
	)
	(segment
		(start 40.382952 -283.306012)
		(end 39.771066 -283.917898)
		(width 0.18288)
		(layer "In6.Cu")
		(net "M_C_CPU1_SA_DQS_DN<8>")
	)
	(segment
		(start 61.313314 -275.988018)
		(end 60.764674 -275.988018)
		(width 0.18288)
		(layer "In6.Cu")
		(net "M_C_CPU1_SA_DQS_DN<8>")
	)
	(segment
		(start 91.827096 -264.989818)
		(end 91.816682 -264.995914)
		(width 0.088646)
		(layer "In6.Cu")
		(net "M_C_CPU1_SA_DQS_DN<8>")
	)
	(segment
		(start 59.357006 -275.863558)
		(end 58.72734 -276.493224)
		(width 0.18288)
		(layer "In6.Cu")
		(net "M_C_CPU1_SA_DQS_DN<8>")
	)
	(segment
		(start 60.764674 -275.988018)
		(end 60.640214 -275.863558)
		(width 0.18288)
		(layer "In6.Cu")
		(net "M_C_CPU1_SA_DQS_DN<8>")
	)
	(segment
		(start 61.437774 -275.863558)
		(end 61.313314 -275.988018)
		(width 0.18288)
		(layer "In6.Cu")
		(net "M_C_CPU1_SA_DQS_DN<8>")
	)
	(segment
		(start 64.248792 -276.280626)
		(end 63.29045 -276.280626)
		(width 0.18288)
		(layer "In6.Cu")
		(net "M_C_CPU1_SA_DQS_DN<8>")
	)
	(segment
		(start 45.699426 -279.900888)
		(end 44.092622 -281.507692)
		(width 0.18288)
		(layer "In6.Cu")
		(net "M_C_CPU1_SA_DQS_DN<8>")
	)
	(segment
		(start 47.244508 -280.191972)
		(end 46.76648 -280.191972)
		(width 0.18288)
		(layer "In6.Cu")
		(net "M_C_CPU1_SA_DQS_DN<8>")
	)
	(segment
		(start 51.601624 -279.084786)
		(end 51.344576 -279.341834)
		(width 0.18288)
		(layer "In6.Cu")
		(net "M_C_CPU1_SA_DQS_DN<8>")
	)
	(segment
		(start 49.941226 -279.063196)
		(end 49.092358 -279.912064)
		(width 0.18288)
		(layer "In6.Cu")
		(net "M_C_CPU1_SA_DQS_DN<8>")
	)
	(segment
		(start 83.039204 -267.14577)
		(end 82.157062 -267.14577)
		(width 0.18288)
		(layer "In6.Cu")
		(net "M_C_CPU1_SA_DQS_DN<8>")
	)
	(segment
		(start 95.035878 -264.998454)
		(end 95.021146 -264.989818)
		(width 0.088646)
		(layer "In6.Cu")
		(net "M_C_CPU1_SA_DQS_DN<8>")
	)
	(segment
		(start 54.157118 -277.550372)
		(end 52.622704 -279.084786)
		(width 0.18288)
		(layer "In6.Cu")
		(net "M_C_CPU1_SA_DQS_DN<8>")
	)
	(segment
		(start 55.993792 -276.493224)
		(end 54.936644 -277.550372)
		(width 0.18288)
		(layer "In6.Cu")
		(net "M_C_CPU1_SA_DQS_DN<8>")
	)
	(segment
		(start 44.092622 -281.507692)
		(end 43.286172 -281.507692)
		(width 0.18288)
		(layer "In6.Cu")
		(net "M_C_CPU1_SA_DQS_DN<8>")
	)
	(segment
		(start 83.062572 -267.14577)
		(end 83.039204 -267.14577)
		(width 0.088646)
		(layer "In6.Cu")
		(net "M_C_CPU1_SA_DQS_DN<8>")
	)
	(segment
		(start 57.738772 -276.493224)
		(end 57.614312 -276.617684)
		(width 0.18288)
		(layer "In6.Cu")
		(net "M_C_CPU1_SA_DQS_DN<8>")
	)
	(segment
		(start 47.524416 -279.912064)
		(end 47.244508 -280.191972)
		(width 0.18288)
		(layer "In6.Cu")
		(net "M_C_CPU1_SA_DQS_DN<8>")
	)
	(segment
		(start 41.487852 -283.306012)
		(end 40.382952 -283.306012)
		(width 0.18288)
		(layer "In6.Cu")
		(net "M_C_CPU1_SA_DQS_DN<8>")
	)
	(segment
		(start 92.211906 -264.995914)
		(end 92.201492 -264.989818)
		(width 0.088646)
		(layer "In6.Cu")
		(net "M_C_CPU1_SA_DQS_DN<8>")
	)
	(segment
		(start 94.096078 -264.998454)
		(end 94.081346 -264.989818)
		(width 0.088646)
		(layer "In6.Cu")
		(net "M_C_CPU1_SA_DQS_DN<8>")
	)
	(segment
		(start 39.771066 -283.917898)
		(end 36.796472 -283.917898)
		(width 0.18288)
		(layer "In6.Cu")
		(net "M_C_CPU1_SA_DQS_DN<8>")
	)
	(segment
		(start 79.12608 -268.401038)
		(end 78.544928 -268.401038)
		(width 0.18288)
		(layer "In6.Cu")
		(net "M_C_CPU1_SA_DQS_DN<8>")
	)
	(segment
		(start 49.092358 -279.912064)
		(end 47.524416 -279.912064)
		(width 0.18288)
		(layer "In6.Cu")
		(net "M_C_CPU1_SA_DQS_DN<8>")
	)
	(segment
		(start 83.477862 -267.085826)
		(end 83.122516 -267.085826)
		(width 0.088646)
		(layer "In6.Cu")
		(net "M_C_CPU1_SA_DQS_DN<8>")
	)
	(segment
		(start 96.713548 -265.314176)
		(end 97.026222 -265.314176)
		(width 0.088646)
		(layer "In6.Cu")
		(net "M_C_CPU1_SA_DQS_DN<8>")
	)
	(segment
		(start 50.58791 -279.063196)
		(end 49.941226 -279.063196)
		(width 0.18288)
		(layer "In6.Cu")
		(net "M_C_CPU1_SA_DQS_DN<8>")
	)
	(segment
		(start 97.026222 -265.314176)
		(end 97.083626 -265.256772)
		(width 0.088646)
		(layer "In6.Cu")
		(net "M_C_CPU1_SA_DQS_DN<8>")
	)
	(segment
		(start 43.286172 -281.507692)
		(end 41.487852 -283.306012)
		(width 0.18288)
		(layer "In6.Cu")
		(net "M_C_CPU1_SA_DQS_DN<8>")
	)
	(segment
		(start 46.76648 -280.191972)
		(end 46.475396 -279.900888)
		(width 0.18288)
		(layer "In6.Cu")
		(net "M_C_CPU1_SA_DQS_DN<8>")
	)
	(segment
		(start 36.796472 -283.917898)
		(end 36.616132 -283.737558)
		(width 0.18288)
		(layer "In6.Cu")
		(net "M_C_CPU1_SA_DQS_DN<8>")
	)
	(segment
		(start 78.544928 -268.401038)
		(end 70.951344 -271.547082)
		(width 0.18288)
		(layer "In6.Cu")
		(net "M_C_CPU1_SA_DQS_DN<8>")
	)
	(segment
		(start 60.640214 -275.863558)
		(end 59.357006 -275.863558)
		(width 0.18288)
		(layer "In6.Cu")
		(net "M_C_CPU1_SA_DQS_DN<8>")
	)
	(segment
		(start 84.700618 -265.86307)
		(end 83.477862 -267.085826)
		(width 0.088646)
		(layer "In6.Cu")
		(net "M_C_CPU1_SA_DQS_DN<8>")
	)
	(segment
		(start 67.73545 -274.762976)
		(end 65.766442 -274.762976)
		(width 0.18288)
		(layer "In6.Cu")
		(net "M_C_CPU1_SA_DQS_DN<8>")
	)
	(segment
		(start 51.344576 -279.341834)
		(end 50.866548 -279.341834)
		(width 0.18288)
		(layer "In6.Cu")
		(net "M_C_CPU1_SA_DQS_DN<8>")
	)
	(segment
		(start 36.25596 -283.737558)
		(end 35.976814 -284.016704)
		(width 0.18288)
		(layer "In6.Cu")
		(net "M_C_CPU1_SA_DQS_DN<8>")
	)
	(segment
		(start 50.866548 -279.341834)
		(end 50.58791 -279.063196)
		(width 0.18288)
		(layer "In6.Cu")
		(net "M_C_CPU1_SA_DQS_DN<8>")
	)
	(segment
		(start 62.873382 -275.863558)
		(end 61.437774 -275.863558)
		(width 0.18288)
		(layer "In6.Cu")
		(net "M_C_CPU1_SA_DQS_DN<8>")
	)
	(segment
		(start 57.065672 -276.617684)
		(end 56.941212 -276.493224)
		(width 0.18288)
		(layer "In6.Cu")
		(net "M_C_CPU1_SA_DQS_DN<8>")
	)
	(segment
		(start 82.157062 -267.14577)
		(end 79.12608 -268.401038)
		(width 0.18288)
		(layer "In6.Cu")
		(net "M_C_CPU1_SA_DQS_DN<8>")
	)
	(arc
		(start 93.141546 -264.989818)
		(mid 92.954348 -264.939675)
		(end 92.76715 -264.989818)
		(width 0.088646)
		(layer "In6.Cu")
		(net "M_C_CPU1_SA_DQS_DN<8>")
	)
	(arc
		(start 89.947496 -264.989818)
		(mid 89.664794 -265.065594)
		(end 89.382092 -264.989818)
		(width 0.088646)
		(layer "In6.Cu")
		(net "M_C_CPU1_SA_DQS_DN<8>")
	)
	(arc
		(start 94.64675 -264.989818)
		(mid 94.372551 -265.065653)
		(end 94.096078 -264.998454)
		(width 0.088646)
		(layer "In6.Cu")
		(net "M_C_CPU1_SA_DQS_DN<8>")
	)
	(arc
		(start 93.70695 -264.989818)
		(mid 93.432751 -265.065653)
		(end 93.156278 -264.998454)
		(width 0.088646)
		(layer "In6.Cu")
		(net "M_C_CPU1_SA_DQS_DN<8>")
	)
	(arc
		(start 84.778596 -265.803634)
		(mid 84.737643 -265.830777)
		(end 84.700618 -265.86307)
		(width 0.088646)
		(layer "In6.Cu")
		(net "M_C_CPU1_SA_DQS_DN<8>")
	)
	(arc
		(start 91.816682 -264.995914)
		(mid 91.538504 -265.065637)
		(end 91.261946 -264.989818)
		(width 0.088646)
		(layer "In6.Cu")
		(net "M_C_CPU1_SA_DQS_DN<8>")
	)
	(arc
		(start 86.562692 -264.989818)
		(mid 86.375494 -264.939675)
		(end 86.188296 -264.989818)
		(width 0.088646)
		(layer "In6.Cu")
		(net "M_C_CPU1_SA_DQS_DN<8>")
	)
	(arc
		(start 89.007696 -264.989818)
		(mid 88.724994 -265.065594)
		(end 88.442292 -264.989818)
		(width 0.088646)
		(layer "In6.Cu")
		(net "M_C_CPU1_SA_DQS_DN<8>")
	)
	(arc
		(start 96.52635 -264.989818)
		(mid 96.252151 -265.065653)
		(end 95.975678 -264.998454)
		(width 0.088646)
		(layer "In6.Cu")
		(net "M_C_CPU1_SA_DQS_DN<8>")
	)
	(arc
		(start 97.083626 -265.256772)
		(mid 96.875382 -264.976233)
		(end 96.52635 -264.989818)
		(width 0.088646)
		(layer "In6.Cu")
		(net "M_C_CPU1_SA_DQS_DN<8>")
	)
	(arc
		(start 92.201492 -264.989818)
		(mid 92.014294 -264.939675)
		(end 91.827096 -264.989818)
		(width 0.088646)
		(layer "In6.Cu")
		(net "M_C_CPU1_SA_DQS_DN<8>")
	)
	(arc
		(start 85.622892 -264.989818)
		(mid 85.248417 -264.989864)
		(end 85.061044 -265.314176)
		(width 0.088646)
		(layer "In6.Cu")
		(net "M_C_CPU1_SA_DQS_DN<8>")
	)
	(arc
		(start 89.382092 -264.989818)
		(mid 89.194894 -264.939675)
		(end 89.007696 -264.989818)
		(width 0.088646)
		(layer "In6.Cu")
		(net "M_C_CPU1_SA_DQS_DN<8>")
	)
	(arc
		(start 95.960946 -264.989818)
		(mid 95.773748 -264.939675)
		(end 95.58655 -264.989818)
		(width 0.088646)
		(layer "In6.Cu")
		(net "M_C_CPU1_SA_DQS_DN<8>")
	)
	(arc
		(start 86.188296 -264.989818)
		(mid 85.905594 -265.065594)
		(end 85.622892 -264.989818)
		(width 0.088646)
		(layer "In6.Cu")
		(net "M_C_CPU1_SA_DQS_DN<8>")
	)
	(arc
		(start 88.067896 -264.989818)
		(mid 87.785194 -265.065594)
		(end 87.502492 -264.989818)
		(width 0.088646)
		(layer "In6.Cu")
		(net "M_C_CPU1_SA_DQS_DN<8>")
	)
	(arc
		(start 94.081346 -264.989818)
		(mid 93.894148 -264.939675)
		(end 93.70695 -264.989818)
		(width 0.088646)
		(layer "In6.Cu")
		(net "M_C_CPU1_SA_DQS_DN<8>")
	)
	(arc
		(start 95.58655 -264.989818)
		(mid 95.312351 -265.065653)
		(end 95.035878 -264.998454)
		(width 0.088646)
		(layer "In6.Cu")
		(net "M_C_CPU1_SA_DQS_DN<8>")
	)
	(arc
		(start 92.76715 -264.989818)
		(mid 92.490337 -265.065688)
		(end 92.211906 -264.995914)
		(width 0.088646)
		(layer "In6.Cu")
		(net "M_C_CPU1_SA_DQS_DN<8>")
	)
	(arc
		(start 87.128096 -264.989818)
		(mid 86.845394 -265.065594)
		(end 86.562692 -264.989818)
		(width 0.088646)
		(layer "In6.Cu")
		(net "M_C_CPU1_SA_DQS_DN<8>")
	)
	(arc
		(start 85.061044 -265.324082)
		(mid 84.982933 -265.601031)
		(end 84.778596 -265.803634)
		(width 0.088646)
		(layer "In6.Cu")
		(net "M_C_CPU1_SA_DQS_DN<8>")
	)
	(arc
		(start 90.88755 -264.989818)
		(mid 90.610737 -265.065688)
		(end 90.332306 -264.995914)
		(width 0.088646)
		(layer "In6.Cu")
		(net "M_C_CPU1_SA_DQS_DN<8>")
	)
	(arc
		(start 88.442292 -264.989818)
		(mid 88.255094 -264.939675)
		(end 88.067896 -264.989818)
		(width 0.088646)
		(layer "In6.Cu")
		(net "M_C_CPU1_SA_DQS_DN<8>")
	)
	(arc
		(start 90.321892 -264.989818)
		(mid 90.134694 -264.939675)
		(end 89.947496 -264.989818)
		(width 0.088646)
		(layer "In6.Cu")
		(net "M_C_CPU1_SA_DQS_DN<8>")
	)
	(arc
		(start 95.021146 -264.989818)
		(mid 94.833948 -264.939675)
		(end 94.64675 -264.989818)
		(width 0.088646)
		(layer "In6.Cu")
		(net "M_C_CPU1_SA_DQS_DN<8>")
	)
	(arc
		(start 87.502492 -264.989818)
		(mid 87.315294 -264.939675)
		(end 87.128096 -264.989818)
		(width 0.088646)
		(layer "In6.Cu")
		(net "M_C_CPU1_SA_DQS_DN<8>")
	)
	(arc
		(start 91.261946 -264.989818)
		(mid 91.074748 -264.939675)
		(end 90.88755 -264.989818)
		(width 0.088646)
		(layer "In6.Cu")
		(net "M_C_CPU1_SA_DQS_DN<8>")
	)
	(segment
		(start 29.895292 -292.941756)
		(end 31.972758 -292.941756)
		(width 0.1016)
		(layer "F.Cu")
		(net "M_C_CPU1_SA_DQS_DN<7>")
	)
	(segment
		(start 29.196284 -292.683184)
		(end 29.464508 -292.951408)
		(width 0.20066)
		(layer "F.Cu")
		(net "M_C_CPU1_SA_DQS_DN<7>")
	)
	(segment
		(start 32.114998 -292.941756)
		(end 32.37611 -292.680644)
		(width 0.20066)
		(layer "F.Cu")
		(net "M_C_CPU1_SA_DQS_DN<7>")
	)
	(segment
		(start 31.972758 -292.941756)
		(end 32.114998 -292.941756)
		(width 0.20066)
		(layer "F.Cu")
		(net "M_C_CPU1_SA_DQS_DN<7>")
	)
	(segment
		(start 28.534106 -293.105586)
		(end 28.956508 -292.683184)
		(width 0.20066)
		(layer "F.Cu")
		(net "M_C_CPU1_SA_DQS_DN<7>")
	)
	(segment
		(start 28.956508 -292.683184)
		(end 29.196284 -292.683184)
		(width 0.20066)
		(layer "F.Cu")
		(net "M_C_CPU1_SA_DQS_DN<7>")
	)
	(segment
		(start 32.37611 -292.680644)
		(end 32.780732 -292.680644)
		(width 0.20066)
		(layer "F.Cu")
		(net "M_C_CPU1_SA_DQS_DN<7>")
	)
	(segment
		(start 29.647642 -292.951408)
		(end 29.649166 -292.951408)
		(width 0.101854)
		(layer "F.Cu")
		(net "M_C_CPU1_SA_DQS_DN<7>")
	)
	(segment
		(start 28.060904 -293.105586)
		(end 28.534106 -293.105586)
		(width 0.20066)
		(layer "F.Cu")
		(net "M_C_CPU1_SA_DQS_DN<7>")
	)
	(segment
		(start 27.799792 -293.366698)
		(end 28.060904 -293.105586)
		(width 0.20066)
		(layer "F.Cu")
		(net "M_C_CPU1_SA_DQS_DN<7>")
	)
	(segment
		(start 94.364048 -267.219938)
		(end 94.363794 -267.755878)
		(width 0.20066)
		(layer "F.Cu")
		(net "M_C_CPU1_SA_DQS_DN<7>")
	)
	(segment
		(start 29.658818 -292.941756)
		(end 29.895292 -292.941756)
		(width 0.101854)
		(layer "F.Cu")
		(net "M_C_CPU1_SA_DQS_DN<7>")
	)
	(segment
		(start 32.780732 -292.680644)
		(end 33.416748 -293.105586)
		(width 0.20066)
		(layer "F.Cu")
		(net "M_C_CPU1_SA_DQS_DN<7>")
	)
	(segment
		(start 34.120328 -293.105586)
		(end 34.38144 -293.366698)
		(width 0.20066)
		(layer "F.Cu")
		(net "M_C_CPU1_SA_DQS_DN<7>")
	)
	(segment
		(start 33.416748 -293.105586)
		(end 34.120328 -293.105586)
		(width 0.20066)
		(layer "F.Cu")
		(net "M_C_CPU1_SA_DQS_DN<7>")
	)
	(segment
		(start 29.649166 -292.951408)
		(end 29.658818 -292.941756)
		(width 0.101854)
		(layer "F.Cu")
		(net "M_C_CPU1_SA_DQS_DN<7>")
	)
	(segment
		(start 29.464508 -292.951408)
		(end 29.647642 -292.951408)
		(width 0.20066)
		(layer "F.Cu")
		(net "M_C_CPU1_SA_DQS_DN<7>")
	)
	(segment
		(start 27.328114 -293.366698)
		(end 27.799792 -293.366698)
		(width 0.20066)
		(layer "F.Cu")
		(net "M_C_CPU1_SA_DQS_DN<7>")
	)
	(segment
		(start 34.38144 -293.366698)
		(end 34.871914 -293.366698)
		(width 0.20066)
		(layer "F.Cu")
		(net "M_C_CPU1_SA_DQS_DN<7>")
	)
	(segment
		(start 35.976814 -293.366698)
		(end 34.871914 -293.366698)
		(width 0.20066)
		(layer "F.Cu")
		(net "M_C_CPU1_SA_DQS_DN<7>")
	)
	(segment
		(start 89.857834 -267.434568)
		(end 89.852246 -267.431266)
		(width 0.088646)
		(layer "In4.Cu")
		(net "M_C_CPU1_SA_DQS_DN<7>")
	)
	(segment
		(start 45.70222 -292.666674)
		(end 45.114972 -292.079426)
		(width 0.18288)
		(layer "In4.Cu")
		(net "M_C_CPU1_SA_DQS_DN<7>")
	)
	(segment
		(start 69.3801 -283.748988)
		(end 67.106292 -286.022796)
		(width 0.18288)
		(layer "In4.Cu")
		(net "M_C_CPU1_SA_DQS_DN<7>")
	)
	(segment
		(start 36.637214 -293.10076)
		(end 36.242752 -293.10076)
		(width 0.18288)
		(layer "In4.Cu")
		(net "M_C_CPU1_SA_DQS_DN<7>")
	)
	(segment
		(start 45.114972 -292.079426)
		(end 44.37507 -292.079426)
		(width 0.18288)
		(layer "In4.Cu")
		(net "M_C_CPU1_SA_DQS_DN<7>")
	)
	(segment
		(start 47.426626 -292.676072)
		(end 47.160688 -292.94201)
		(width 0.18288)
		(layer "In4.Cu")
		(net "M_C_CPU1_SA_DQS_DN<7>")
	)
	(segment
		(start 61.324744 -288.687256)
		(end 58.839608 -291.172392)
		(width 0.18288)
		(layer "In4.Cu")
		(net "M_C_CPU1_SA_DQS_DN<7>")
	)
	(segment
		(start 41.366186 -292.57117)
		(end 39.46017 -293.36111)
		(width 0.18288)
		(layer "In4.Cu")
		(net "M_C_CPU1_SA_DQS_DN<7>")
	)
	(segment
		(start 57.280556 -292.006528)
		(end 56.293766 -292.415722)
		(width 0.18288)
		(layer "In4.Cu")
		(net "M_C_CPU1_SA_DQS_DN<7>")
	)
	(segment
		(start 50.593498 -291.814758)
		(end 50.081942 -291.814758)
		(width 0.18288)
		(layer "In4.Cu")
		(net "M_C_CPU1_SA_DQS_DN<7>")
	)
	(segment
		(start 84.660486 -267.381228)
		(end 83.985608 -268.056106)
		(width 0.088646)
		(layer "In4.Cu")
		(net "M_C_CPU1_SA_DQS_DN<7>")
	)
	(segment
		(start 90.792046 -267.431266)
		(end 90.787474 -267.428726)
		(width 0.088646)
		(layer "In4.Cu")
		(net "M_C_CPU1_SA_DQS_DN<7>")
	)
	(segment
		(start 83.985608 -268.056106)
		(end 83.985608 -268.555978)
		(width 0.088646)
		(layer "In4.Cu")
		(net "M_C_CPU1_SA_DQS_DN<7>")
	)
	(segment
		(start 92.780358 -267.49502)
		(end 92.671646 -267.431266)
		(width 0.088646)
		(layer "In4.Cu")
		(net "M_C_CPU1_SA_DQS_DN<7>")
	)
	(segment
		(start 83.985608 -268.555978)
		(end 83.78571 -268.755876)
		(width 0.088646)
		(layer "In4.Cu")
		(net "M_C_CPU1_SA_DQS_DN<7>")
	)
	(segment
		(start 83.78571 -268.755876)
		(end 83.579716 -268.755876)
		(width 0.088646)
		(layer "In4.Cu")
		(net "M_C_CPU1_SA_DQS_DN<7>")
	)
	(segment
		(start 58.839608 -291.172392)
		(end 57.280556 -292.006528)
		(width 0.18288)
		(layer "In4.Cu")
		(net "M_C_CPU1_SA_DQS_DN<7>")
	)
	(segment
		(start 91.739212 -267.435584)
		(end 91.731846 -267.431266)
		(width 0.088646)
		(layer "In4.Cu")
		(net "M_C_CPU1_SA_DQS_DN<7>")
	)
	(segment
		(start 46.770544 -292.94201)
		(end 46.495208 -292.666674)
		(width 0.18288)
		(layer "In4.Cu")
		(net "M_C_CPU1_SA_DQS_DN<7>")
	)
	(segment
		(start 66.59499 -286.743394)
		(end 66.331084 -287.0073)
		(width 0.18288)
		(layer "In4.Cu")
		(net "M_C_CPU1_SA_DQS_DN<7>")
	)
	(segment
		(start 83.519772 -268.81582)
		(end 83.496404 -268.81582)
		(width 0.088646)
		(layer "In4.Cu")
		(net "M_C_CPU1_SA_DQS_DN<7>")
	)
	(segment
		(start 47.160688 -292.94201)
		(end 46.770544 -292.94201)
		(width 0.18288)
		(layer "In4.Cu")
		(net "M_C_CPU1_SA_DQS_DN<7>")
	)
	(segment
		(start 88.917018 -267.43406)
		(end 88.912192 -267.43152)
		(width 0.088646)
		(layer "In4.Cu")
		(net "M_C_CPU1_SA_DQS_DN<7>")
	)
	(segment
		(start 54.975506 -292.075362)
		(end 53.037232 -292.075362)
		(width 0.18288)
		(layer "In4.Cu")
		(net "M_C_CPU1_SA_DQS_DN<7>")
	)
	(segment
		(start 50.870612 -292.091872)
		(end 50.593498 -291.814758)
		(width 0.18288)
		(layer "In4.Cu")
		(net "M_C_CPU1_SA_DQS_DN<7>")
	)
	(segment
		(start 81.99501 -268.81582)
		(end 71.018146 -279.792684)
		(width 0.18288)
		(layer "In4.Cu")
		(net "M_C_CPU1_SA_DQS_DN<7>")
	)
	(segment
		(start 83.579716 -268.755876)
		(end 83.519772 -268.81582)
		(width 0.088646)
		(layer "In4.Cu")
		(net "M_C_CPU1_SA_DQS_DN<7>")
	)
	(segment
		(start 62.905386 -288.687256)
		(end 61.324744 -288.687256)
		(width 0.18288)
		(layer "In4.Cu")
		(net "M_C_CPU1_SA_DQS_DN<7>")
	)
	(segment
		(start 46.495208 -292.666674)
		(end 45.70222 -292.666674)
		(width 0.18288)
		(layer "In4.Cu")
		(net "M_C_CPU1_SA_DQS_DN<7>")
	)
	(segment
		(start 90.799412 -267.435584)
		(end 90.792046 -267.431266)
		(width 0.088646)
		(layer "In4.Cu")
		(net "M_C_CPU1_SA_DQS_DN<7>")
	)
	(segment
		(start 63.765684 -287.826958)
		(end 62.905386 -288.687256)
		(width 0.18288)
		(layer "In4.Cu")
		(net "M_C_CPU1_SA_DQS_DN<7>")
	)
	(segment
		(start 36.242752 -293.10076)
		(end 35.976814 -293.366698)
		(width 0.18288)
		(layer "In4.Cu")
		(net "M_C_CPU1_SA_DQS_DN<7>")
	)
	(segment
		(start 66.59499 -286.357314)
		(end 66.59499 -286.743394)
		(width 0.18288)
		(layer "In4.Cu")
		(net "M_C_CPU1_SA_DQS_DN<7>")
	)
	(segment
		(start 65.682368 -287.250886)
		(end 64.291718 -287.826958)
		(width 0.18288)
		(layer "In4.Cu")
		(net "M_C_CPU1_SA_DQS_DN<7>")
	)
	(segment
		(start 55.797196 -292.415722)
		(end 54.975506 -292.075362)
		(width 0.18288)
		(layer "In4.Cu")
		(net "M_C_CPU1_SA_DQS_DN<7>")
	)
	(segment
		(start 83.496404 -268.81582)
		(end 81.99501 -268.81582)
		(width 0.18288)
		(layer "In4.Cu")
		(net "M_C_CPU1_SA_DQS_DN<7>")
	)
	(segment
		(start 66.804794 -286.14751)
		(end 66.59499 -286.357314)
		(width 0.18288)
		(layer "In4.Cu")
		(net "M_C_CPU1_SA_DQS_DN<7>")
	)
	(segment
		(start 65.925954 -287.0073)
		(end 65.682368 -287.250886)
		(width 0.18288)
		(layer "In4.Cu")
		(net "M_C_CPU1_SA_DQS_DN<7>")
	)
	(segment
		(start 36.897564 -293.36111)
		(end 36.637214 -293.10076)
		(width 0.18288)
		(layer "In4.Cu")
		(net "M_C_CPU1_SA_DQS_DN<7>")
	)
	(segment
		(start 39.46017 -293.36111)
		(end 36.897564 -293.36111)
		(width 0.18288)
		(layer "In4.Cu")
		(net "M_C_CPU1_SA_DQS_DN<7>")
	)
	(segment
		(start 51.510946 -291.823394)
		(end 51.242468 -292.091872)
		(width 0.18288)
		(layer "In4.Cu")
		(net "M_C_CPU1_SA_DQS_DN<7>")
	)
	(segment
		(start 50.081942 -291.814758)
		(end 49.220628 -292.676072)
		(width 0.18288)
		(layer "In4.Cu")
		(net "M_C_CPU1_SA_DQS_DN<7>")
	)
	(segment
		(start 67.106292 -286.022796)
		(end 66.804794 -286.14751)
		(width 0.18288)
		(layer "In4.Cu")
		(net "M_C_CPU1_SA_DQS_DN<7>")
	)
	(segment
		(start 64.291718 -287.826958)
		(end 63.765684 -287.826958)
		(width 0.18288)
		(layer "In4.Cu")
		(net "M_C_CPU1_SA_DQS_DN<7>")
	)
	(segment
		(start 71.018146 -279.792684)
		(end 69.3801 -283.748988)
		(width 0.18288)
		(layer "In4.Cu")
		(net "M_C_CPU1_SA_DQS_DN<7>")
	)
	(segment
		(start 49.220628 -292.676072)
		(end 47.426626 -292.676072)
		(width 0.18288)
		(layer "In4.Cu")
		(net "M_C_CPU1_SA_DQS_DN<7>")
	)
	(segment
		(start 56.293766 -292.415722)
		(end 55.797196 -292.415722)
		(width 0.18288)
		(layer "In4.Cu")
		(net "M_C_CPU1_SA_DQS_DN<7>")
	)
	(segment
		(start 43.883326 -292.57117)
		(end 41.366186 -292.57117)
		(width 0.18288)
		(layer "In4.Cu")
		(net "M_C_CPU1_SA_DQS_DN<7>")
	)
	(segment
		(start 93.236796 -268.080236)
		(end 93.222064 -268.0716)
		(width 0.088646)
		(layer "In4.Cu")
		(net "M_C_CPU1_SA_DQS_DN<7>")
	)
	(segment
		(start 44.37507 -292.079426)
		(end 43.883326 -292.57117)
		(width 0.18288)
		(layer "In4.Cu")
		(net "M_C_CPU1_SA_DQS_DN<7>")
	)
	(segment
		(start 66.331084 -287.0073)
		(end 65.925954 -287.0073)
		(width 0.18288)
		(layer "In4.Cu")
		(net "M_C_CPU1_SA_DQS_DN<7>")
	)
	(segment
		(start 53.037232 -292.075362)
		(end 52.428648 -291.823394)
		(width 0.18288)
		(layer "In4.Cu")
		(net "M_C_CPU1_SA_DQS_DN<7>")
	)
	(segment
		(start 52.428648 -291.823394)
		(end 51.510946 -291.823394)
		(width 0.18288)
		(layer "In4.Cu")
		(net "M_C_CPU1_SA_DQS_DN<7>")
	)
	(segment
		(start 51.242468 -292.091872)
		(end 50.870612 -292.091872)
		(width 0.18288)
		(layer "In4.Cu")
		(net "M_C_CPU1_SA_DQS_DN<7>")
	)
	(segment
		(start 91.731846 -267.431266)
		(end 91.727274 -267.428726)
		(width 0.088646)
		(layer "In4.Cu")
		(net "M_C_CPU1_SA_DQS_DN<7>")
	)
	(segment
		(start 84.965286 -267.381228)
		(end 84.660486 -267.381228)
		(width 0.088646)
		(layer "In4.Cu")
		(net "M_C_CPU1_SA_DQS_DN<7>")
	)
	(segment
		(start 92.671646 -267.431266)
		(end 92.667074 -267.428726)
		(width 0.088646)
		(layer "In4.Cu")
		(net "M_C_CPU1_SA_DQS_DN<7>")
	)
	(arc
		(start 90.787474 -267.428726)
		(mid 90.602089 -267.381088)
		(end 90.417396 -267.431266)
		(width 0.088646)
		(layer "In4.Cu")
		(net "M_C_CPU1_SA_DQS_DN<7>")
	)
	(arc
		(start 85.152992 -267.43152)
		(mid 85.06245 -267.394017)
		(end 84.965286 -267.381228)
		(width 0.088646)
		(layer "In4.Cu")
		(net "M_C_CPU1_SA_DQS_DN<7>")
	)
	(arc
		(start 92.296996 -267.431266)
		(mid 92.018673 -267.507025)
		(end 91.739212 -267.435584)
		(width 0.088646)
		(layer "In4.Cu")
		(net "M_C_CPU1_SA_DQS_DN<7>")
	)
	(arc
		(start 91.357196 -267.431266)
		(mid 91.078873 -267.507025)
		(end 90.799412 -267.435584)
		(width 0.088646)
		(layer "In4.Cu")
		(net "M_C_CPU1_SA_DQS_DN<7>")
	)
	(arc
		(start 86.092792 -267.43152)
		(mid 85.905594 -267.381377)
		(end 85.718396 -267.43152)
		(width 0.088646)
		(layer "In4.Cu")
		(net "M_C_CPU1_SA_DQS_DN<7>")
	)
	(arc
		(start 93.222064 -268.0716)
		(mid 93.037591 -267.920235)
		(end 92.908882 -267.719302)
		(width 0.088646)
		(layer "In4.Cu")
		(net "M_C_CPU1_SA_DQS_DN<7>")
	)
	(arc
		(start 88.537796 -267.43152)
		(mid 88.255094 -267.507262)
		(end 87.972392 -267.43152)
		(width 0.088646)
		(layer "In4.Cu")
		(net "M_C_CPU1_SA_DQS_DN<7>")
	)
	(arc
		(start 87.597996 -267.43152)
		(mid 87.315294 -267.507262)
		(end 87.032592 -267.43152)
		(width 0.088646)
		(layer "In4.Cu")
		(net "M_C_CPU1_SA_DQS_DN<7>")
	)
	(arc
		(start 91.727274 -267.428726)
		(mid 91.541889 -267.381088)
		(end 91.357196 -267.431266)
		(width 0.088646)
		(layer "In4.Cu")
		(net "M_C_CPU1_SA_DQS_DN<7>")
	)
	(arc
		(start 87.032592 -267.43152)
		(mid 86.845394 -267.381377)
		(end 86.658196 -267.43152)
		(width 0.088646)
		(layer "In4.Cu")
		(net "M_C_CPU1_SA_DQS_DN<7>")
	)
	(arc
		(start 88.912192 -267.43152)
		(mid 88.724994 -267.381377)
		(end 88.537796 -267.43152)
		(width 0.088646)
		(layer "In4.Cu")
		(net "M_C_CPU1_SA_DQS_DN<7>")
	)
	(arc
		(start 87.972392 -267.43152)
		(mid 87.785194 -267.381377)
		(end 87.597996 -267.43152)
		(width 0.088646)
		(layer "In4.Cu")
		(net "M_C_CPU1_SA_DQS_DN<7>")
	)
	(arc
		(start 94.363794 -267.755878)
		(mid 93.978034 -267.896109)
		(end 93.611192 -268.080236)
		(width 0.088646)
		(layer "In4.Cu")
		(net "M_C_CPU1_SA_DQS_DN<7>")
	)
	(arc
		(start 85.718396 -267.43152)
		(mid 85.435694 -267.507262)
		(end 85.152992 -267.43152)
		(width 0.088646)
		(layer "In4.Cu")
		(net "M_C_CPU1_SA_DQS_DN<7>")
	)
	(arc
		(start 89.852246 -267.431266)
		(mid 89.664938 -267.381157)
		(end 89.477596 -267.431266)
		(width 0.088646)
		(layer "In4.Cu")
		(net "M_C_CPU1_SA_DQS_DN<7>")
	)
	(arc
		(start 92.908882 -267.719302)
		(mid 92.874485 -267.590036)
		(end 92.780358 -267.49502)
		(width 0.088646)
		(layer "In4.Cu")
		(net "M_C_CPU1_SA_DQS_DN<7>")
	)
	(arc
		(start 90.417396 -267.431266)
		(mid 90.138049 -267.507032)
		(end 89.857834 -267.434568)
		(width 0.088646)
		(layer "In4.Cu")
		(net "M_C_CPU1_SA_DQS_DN<7>")
	)
	(arc
		(start 86.658196 -267.43152)
		(mid 86.375494 -267.507262)
		(end 86.092792 -267.43152)
		(width 0.088646)
		(layer "In4.Cu")
		(net "M_C_CPU1_SA_DQS_DN<7>")
	)
	(arc
		(start 89.477596 -267.431266)
		(mid 89.197682 -267.507035)
		(end 88.917018 -267.43406)
		(width 0.088646)
		(layer "In4.Cu")
		(net "M_C_CPU1_SA_DQS_DN<7>")
	)
	(arc
		(start 92.667074 -267.428726)
		(mid 92.481689 -267.381088)
		(end 92.296996 -267.431266)
		(width 0.088646)
		(layer "In4.Cu")
		(net "M_C_CPU1_SA_DQS_DN<7>")
	)
	(arc
		(start 93.611192 -268.080236)
		(mid 93.423994 -268.130379)
		(end 93.236796 -268.080236)
		(width 0.088646)
		(layer "In4.Cu")
		(net "M_C_CPU1_SA_DQS_DN<7>")
	)
	(segment
		(start 34.120328 -302.45558)
		(end 34.38144 -302.716692)
		(width 0.20066)
		(layer "F.Cu")
		(net "M_C_CPU1_SA_DQS_DN<6>")
	)
	(segment
		(start 97.653094 -269.66164)
		(end 97.653348 -270.19758)
		(width 0.20066)
		(layer "F.Cu")
		(net "M_C_CPU1_SA_DQS_DN<6>")
	)
	(segment
		(start 27.328114 -302.716692)
		(end 27.799792 -302.716692)
		(width 0.20066)
		(layer "F.Cu")
		(net "M_C_CPU1_SA_DQS_DN<6>")
	)
	(segment
		(start 32.114998 -302.29175)
		(end 32.37611 -302.030638)
		(width 0.20066)
		(layer "F.Cu")
		(net "M_C_CPU1_SA_DQS_DN<6>")
	)
	(segment
		(start 32.37611 -302.030638)
		(end 32.780732 -302.030638)
		(width 0.20066)
		(layer "F.Cu")
		(net "M_C_CPU1_SA_DQS_DN<6>")
	)
	(segment
		(start 29.895292 -302.29175)
		(end 31.972758 -302.29175)
		(width 0.1016)
		(layer "F.Cu")
		(net "M_C_CPU1_SA_DQS_DN<6>")
	)
	(segment
		(start 29.647642 -302.301402)
		(end 29.649166 -302.301402)
		(width 0.101854)
		(layer "F.Cu")
		(net "M_C_CPU1_SA_DQS_DN<6>")
	)
	(segment
		(start 35.976814 -302.716692)
		(end 34.871914 -302.716692)
		(width 0.20066)
		(layer "F.Cu")
		(net "M_C_CPU1_SA_DQS_DN<6>")
	)
	(segment
		(start 28.534106 -302.45558)
		(end 28.956508 -302.033178)
		(width 0.20066)
		(layer "F.Cu")
		(net "M_C_CPU1_SA_DQS_DN<6>")
	)
	(segment
		(start 32.780732 -302.030638)
		(end 33.416748 -302.45558)
		(width 0.20066)
		(layer "F.Cu")
		(net "M_C_CPU1_SA_DQS_DN<6>")
	)
	(segment
		(start 28.060904 -302.45558)
		(end 28.534106 -302.45558)
		(width 0.20066)
		(layer "F.Cu")
		(net "M_C_CPU1_SA_DQS_DN<6>")
	)
	(segment
		(start 29.196284 -302.033178)
		(end 29.464508 -302.301402)
		(width 0.20066)
		(layer "F.Cu")
		(net "M_C_CPU1_SA_DQS_DN<6>")
	)
	(segment
		(start 31.972758 -302.29175)
		(end 32.114998 -302.29175)
		(width 0.20066)
		(layer "F.Cu")
		(net "M_C_CPU1_SA_DQS_DN<6>")
	)
	(segment
		(start 34.38144 -302.716692)
		(end 34.871914 -302.716692)
		(width 0.20066)
		(layer "F.Cu")
		(net "M_C_CPU1_SA_DQS_DN<6>")
	)
	(segment
		(start 29.649166 -302.301402)
		(end 29.658818 -302.29175)
		(width 0.101854)
		(layer "F.Cu")
		(net "M_C_CPU1_SA_DQS_DN<6>")
	)
	(segment
		(start 28.956508 -302.033178)
		(end 29.196284 -302.033178)
		(width 0.20066)
		(layer "F.Cu")
		(net "M_C_CPU1_SA_DQS_DN<6>")
	)
	(segment
		(start 29.464508 -302.301402)
		(end 29.647642 -302.301402)
		(width 0.20066)
		(layer "F.Cu")
		(net "M_C_CPU1_SA_DQS_DN<6>")
	)
	(segment
		(start 33.416748 -302.45558)
		(end 34.120328 -302.45558)
		(width 0.20066)
		(layer "F.Cu")
		(net "M_C_CPU1_SA_DQS_DN<6>")
	)
	(segment
		(start 29.658818 -302.29175)
		(end 29.895292 -302.29175)
		(width 0.101854)
		(layer "F.Cu")
		(net "M_C_CPU1_SA_DQS_DN<6>")
	)
	(segment
		(start 27.799792 -302.716692)
		(end 28.060904 -302.45558)
		(width 0.20066)
		(layer "F.Cu")
		(net "M_C_CPU1_SA_DQS_DN<6>")
	)
	(segment
		(start 90.332306 -269.879318)
		(end 90.321892 -269.873222)
		(width 0.088646)
		(layer "In6.Cu")
		(net "M_C_CPU1_SA_DQS_DN<6>")
	)
	(segment
		(start 83.70316 -273.252184)
		(end 83.4263 -273.252184)
		(width 0.088646)
		(layer "In6.Cu")
		(net "M_C_CPU1_SA_DQS_DN<6>")
	)
	(segment
		(start 41.705276 -295.263062)
		(end 41.155112 -295.263062)
		(width 0.18288)
		(layer "In6.Cu")
		(net "M_C_CPU1_SA_DQS_DN<6>")
	)
	(segment
		(start 83.342988 -273.312128)
		(end 82.724752 -273.312128)
		(width 0.18288)
		(layer "In6.Cu")
		(net "M_C_CPU1_SA_DQS_DN<6>")
	)
	(segment
		(start 51.58994 -291.811964)
		(end 51.310032 -292.091872)
		(width 0.18288)
		(layer "In6.Cu")
		(net "M_C_CPU1_SA_DQS_DN<6>")
	)
	(segment
		(start 44.891452 -293.683944)
		(end 43.284394 -293.683944)
		(width 0.18288)
		(layer "In6.Cu")
		(net "M_C_CPU1_SA_DQS_DN<6>")
	)
	(segment
		(start 43.284394 -293.683944)
		(end 41.705276 -295.263062)
		(width 0.18288)
		(layer "In6.Cu")
		(net "M_C_CPU1_SA_DQS_DN<6>")
	)
	(segment
		(start 83.982814 -272.585434)
		(end 83.982814 -272.97253)
		(width 0.088646)
		(layer "In6.Cu")
		(net "M_C_CPU1_SA_DQS_DN<6>")
	)
	(segment
		(start 40.772842 -295.645332)
		(end 40.772842 -300.260004)
		(width 0.18288)
		(layer "In6.Cu")
		(net "M_C_CPU1_SA_DQS_DN<6>")
	)
	(segment
		(start 46.76648 -292.94201)
		(end 46.475396 -292.650926)
		(width 0.18288)
		(layer "In6.Cu")
		(net "M_C_CPU1_SA_DQS_DN<6>")
	)
	(segment
		(start 50.822352 -292.091872)
		(end 50.554128 -291.823648)
		(width 0.18288)
		(layer "In6.Cu")
		(net "M_C_CPU1_SA_DQS_DN<6>")
	)
	(segment
		(start 96.318324 -270.079724)
		(end 95.960692 -269.873222)
		(width 0.088646)
		(layer "In6.Cu")
		(net "M_C_CPU1_SA_DQS_DN<6>")
	)
	(segment
		(start 48.637698 -292.662102)
		(end 47.450248 -292.662102)
		(width 0.18288)
		(layer "In6.Cu")
		(net "M_C_CPU1_SA_DQS_DN<6>")
	)
	(segment
		(start 84.429092 -271.912588)
		(end 84.429092 -272.139156)
		(width 0.088646)
		(layer "In6.Cu")
		(net "M_C_CPU1_SA_DQS_DN<6>")
	)
	(segment
		(start 82.724752 -273.312128)
		(end 76.275184 -275.9837)
		(width 0.18288)
		(layer "In6.Cu")
		(net "M_C_CPU1_SA_DQS_DN<6>")
	)
	(segment
		(start 47.450248 -292.662102)
		(end 47.17034 -292.94201)
		(width 0.18288)
		(layer "In6.Cu")
		(net "M_C_CPU1_SA_DQS_DN<6>")
	)
	(segment
		(start 87.128096 -269.873222)
		(end 87.119206 -269.878302)
		(width 0.088646)
		(layer "In6.Cu")
		(net "M_C_CPU1_SA_DQS_DN<6>")
	)
	(segment
		(start 95.035878 -269.881858)
		(end 95.021146 -269.873222)
		(width 0.088646)
		(layer "In6.Cu")
		(net "M_C_CPU1_SA_DQS_DN<6>")
	)
	(segment
		(start 39.942516 -301.09033)
		(end 38.440868 -301.712376)
		(width 0.18288)
		(layer "In6.Cu")
		(net "M_C_CPU1_SA_DQS_DN<6>")
	)
	(segment
		(start 94.096078 -269.881858)
		(end 94.081346 -269.873222)
		(width 0.088646)
		(layer "In6.Cu")
		(net "M_C_CPU1_SA_DQS_DN<6>")
	)
	(segment
		(start 66.08445 -284.37967)
		(end 64.492124 -285.971996)
		(width 0.18288)
		(layer "In6.Cu")
		(net "M_C_CPU1_SA_DQS_DN<6>")
	)
	(segment
		(start 57.125616 -289.074098)
		(end 54.51602 -290.15563)
		(width 0.18288)
		(layer "In6.Cu")
		(net "M_C_CPU1_SA_DQS_DN<6>")
	)
	(segment
		(start 67.882008 -284.37967)
		(end 66.08445 -284.37967)
		(width 0.18288)
		(layer "In6.Cu")
		(net "M_C_CPU1_SA_DQS_DN<6>")
	)
	(segment
		(start 41.155112 -295.263062)
		(end 40.772842 -295.645332)
		(width 0.18288)
		(layer "In6.Cu")
		(net "M_C_CPU1_SA_DQS_DN<6>")
	)
	(segment
		(start 47.17034 -292.94201)
		(end 46.76648 -292.94201)
		(width 0.18288)
		(layer "In6.Cu")
		(net "M_C_CPU1_SA_DQS_DN<6>")
	)
	(segment
		(start 36.808156 -302.639984)
		(end 36.613084 -302.444912)
		(width 0.18288)
		(layer "In6.Cu")
		(net "M_C_CPU1_SA_DQS_DN<6>")
	)
	(segment
		(start 95.960692 -269.873222)
		(end 95.960946 -269.873222)
		(width 0.088646)
		(layer "In6.Cu")
		(net "M_C_CPU1_SA_DQS_DN<6>")
	)
	(segment
		(start 96.338898 -270.099536)
		(end 96.318324 -270.079724)
		(width 0.088646)
		(layer "In6.Cu")
		(net "M_C_CPU1_SA_DQS_DN<6>")
	)
	(segment
		(start 92.211906 -269.879318)
		(end 92.201492 -269.873222)
		(width 0.088646)
		(layer "In6.Cu")
		(net "M_C_CPU1_SA_DQS_DN<6>")
	)
	(segment
		(start 59.186318 -287.115758)
		(end 58.876946 -287.322514)
		(width 0.18288)
		(layer "In6.Cu")
		(net "M_C_CPU1_SA_DQS_DN<6>")
	)
	(segment
		(start 83.982814 -272.97253)
		(end 83.70316 -273.252184)
		(width 0.088646)
		(layer "In6.Cu")
		(net "M_C_CPU1_SA_DQS_DN<6>")
	)
	(segment
		(start 76.275184 -275.9837)
		(end 67.882008 -284.37967)
		(width 0.18288)
		(layer "In6.Cu")
		(net "M_C_CPU1_SA_DQS_DN<6>")
	)
	(segment
		(start 63.289688 -285.971996)
		(end 62.299596 -286.962088)
		(width 0.18288)
		(layer "In6.Cu")
		(net "M_C_CPU1_SA_DQS_DN<6>")
	)
	(segment
		(start 45.92447 -292.650926)
		(end 44.891452 -293.683944)
		(width 0.18288)
		(layer "In6.Cu")
		(net "M_C_CPU1_SA_DQS_DN<6>")
	)
	(segment
		(start 83.4263 -273.252184)
		(end 83.366356 -273.312128)
		(width 0.088646)
		(layer "In6.Cu")
		(net "M_C_CPU1_SA_DQS_DN<6>")
	)
	(segment
		(start 36.613084 -302.444912)
		(end 36.248594 -302.444912)
		(width 0.18288)
		(layer "In6.Cu")
		(net "M_C_CPU1_SA_DQS_DN<6>")
	)
	(segment
		(start 51.310032 -292.091872)
		(end 50.822352 -292.091872)
		(width 0.18288)
		(layer "In6.Cu")
		(net "M_C_CPU1_SA_DQS_DN<6>")
	)
	(segment
		(start 85.718396 -270.687038)
		(end 85.709506 -270.692118)
		(width 0.088646)
		(layer "In6.Cu")
		(net "M_C_CPU1_SA_DQS_DN<6>")
	)
	(segment
		(start 96.930718 -270.504666)
		(end 96.902778 -270.520922)
		(width 0.088646)
		(layer "In6.Cu")
		(net "M_C_CPU1_SA_DQS_DN<6>")
	)
	(segment
		(start 58.876946 -287.322514)
		(end 57.125616 -289.074098)
		(width 0.18288)
		(layer "In6.Cu")
		(net "M_C_CPU1_SA_DQS_DN<6>")
	)
	(segment
		(start 84.429092 -272.139156)
		(end 83.982814 -272.585434)
		(width 0.088646)
		(layer "In6.Cu")
		(net "M_C_CPU1_SA_DQS_DN<6>")
	)
	(segment
		(start 49.518316 -292.297104)
		(end 48.637698 -292.662102)
		(width 0.18288)
		(layer "In6.Cu")
		(net "M_C_CPU1_SA_DQS_DN<6>")
	)
	(segment
		(start 62.299596 -286.962088)
		(end 59.557158 -286.962088)
		(width 0.18288)
		(layer "In6.Cu")
		(net "M_C_CPU1_SA_DQS_DN<6>")
	)
	(segment
		(start 86.940644 -270.19758)
		(end 86.940644 -270.207486)
		(width 0.088646)
		(layer "In6.Cu")
		(net "M_C_CPU1_SA_DQS_DN<6>")
	)
	(segment
		(start 46.475396 -292.650926)
		(end 45.92447 -292.650926)
		(width 0.18288)
		(layer "In6.Cu")
		(net "M_C_CPU1_SA_DQS_DN<6>")
	)
	(segment
		(start 84.765134 -271.576546)
		(end 84.429092 -271.912588)
		(width 0.088646)
		(layer "In6.Cu")
		(net "M_C_CPU1_SA_DQS_DN<6>")
	)
	(segment
		(start 54.51602 -290.15563)
		(end 52.859686 -291.811964)
		(width 0.18288)
		(layer "In6.Cu")
		(net "M_C_CPU1_SA_DQS_DN<6>")
	)
	(segment
		(start 37.51326 -302.639984)
		(end 36.808156 -302.639984)
		(width 0.18288)
		(layer "In6.Cu")
		(net "M_C_CPU1_SA_DQS_DN<6>")
	)
	(segment
		(start 64.492124 -285.971996)
		(end 63.289688 -285.971996)
		(width 0.18288)
		(layer "In6.Cu")
		(net "M_C_CPU1_SA_DQS_DN<6>")
	)
	(segment
		(start 38.440868 -301.712376)
		(end 37.51326 -302.639984)
		(width 0.18288)
		(layer "In6.Cu")
		(net "M_C_CPU1_SA_DQS_DN<6>")
	)
	(segment
		(start 40.772842 -300.260004)
		(end 39.942516 -301.09033)
		(width 0.18288)
		(layer "In6.Cu")
		(net "M_C_CPU1_SA_DQS_DN<6>")
	)
	(segment
		(start 50.554128 -291.823648)
		(end 49.991772 -291.823648)
		(width 0.18288)
		(layer "In6.Cu")
		(net "M_C_CPU1_SA_DQS_DN<6>")
	)
	(segment
		(start 91.827096 -269.873222)
		(end 91.816682 -269.879318)
		(width 0.088646)
		(layer "In6.Cu")
		(net "M_C_CPU1_SA_DQS_DN<6>")
	)
	(segment
		(start 84.966302 -271.576546)
		(end 84.765134 -271.576546)
		(width 0.088646)
		(layer "In6.Cu")
		(net "M_C_CPU1_SA_DQS_DN<6>")
	)
	(segment
		(start 96.52635 -270.521938)
		(end 96.51746 -270.516858)
		(width 0.088646)
		(layer "In6.Cu")
		(net "M_C_CPU1_SA_DQS_DN<6>")
	)
	(segment
		(start 59.557158 -286.962088)
		(end 59.186318 -287.115758)
		(width 0.18288)
		(layer "In6.Cu")
		(net "M_C_CPU1_SA_DQS_DN<6>")
	)
	(segment
		(start 96.902778 -270.520922)
		(end 96.900746 -270.521938)
		(width 0.088646)
		(layer "In6.Cu")
		(net "M_C_CPU1_SA_DQS_DN<6>")
	)
	(segment
		(start 83.366356 -273.312128)
		(end 83.342988 -273.312128)
		(width 0.088646)
		(layer "In6.Cu")
		(net "M_C_CPU1_SA_DQS_DN<6>")
	)
	(segment
		(start 97.653348 -270.19758)
		(end 96.930718 -270.504666)
		(width 0.088646)
		(layer "In6.Cu")
		(net "M_C_CPU1_SA_DQS_DN<6>")
	)
	(segment
		(start 93.156278 -269.881858)
		(end 93.141546 -269.873222)
		(width 0.088646)
		(layer "In6.Cu")
		(net "M_C_CPU1_SA_DQS_DN<6>")
	)
	(segment
		(start 52.859686 -291.811964)
		(end 51.58994 -291.811964)
		(width 0.18288)
		(layer "In6.Cu")
		(net "M_C_CPU1_SA_DQS_DN<6>")
	)
	(segment
		(start 85.530944 -271.011396)
		(end 85.530944 -271.016222)
		(width 0.088646)
		(layer "In6.Cu")
		(net "M_C_CPU1_SA_DQS_DN<6>")
	)
	(segment
		(start 96.338898 -270.19758)
		(end 96.338898 -270.099536)
		(width 0.088646)
		(layer "In6.Cu")
		(net "M_C_CPU1_SA_DQS_DN<6>")
	)
	(segment
		(start 49.991772 -291.823648)
		(end 49.518316 -292.297104)
		(width 0.18288)
		(layer "In6.Cu")
		(net "M_C_CPU1_SA_DQS_DN<6>")
	)
	(segment
		(start 85.530944 -271.016222)
		(end 85.53069 -271.016476)
		(width 0.088646)
		(layer "In6.Cu")
		(net "M_C_CPU1_SA_DQS_DN<6>")
	)
	(segment
		(start 36.248594 -302.444912)
		(end 35.976814 -302.716692)
		(width 0.18288)
		(layer "In6.Cu")
		(net "M_C_CPU1_SA_DQS_DN<6>")
	)
	(arc
		(start 94.081346 -269.873222)
		(mid 93.894148 -269.823079)
		(end 93.70695 -269.873222)
		(width 0.088646)
		(layer "In6.Cu")
		(net "M_C_CPU1_SA_DQS_DN<6>")
	)
	(arc
		(start 85.53069 -271.016476)
		(mid 85.363648 -271.412557)
		(end 84.966302 -271.576546)
		(width 0.088646)
		(layer "In6.Cu")
		(net "M_C_CPU1_SA_DQS_DN<6>")
	)
	(arc
		(start 88.442292 -269.873222)
		(mid 88.255094 -269.823079)
		(end 88.067896 -269.873222)
		(width 0.088646)
		(layer "In6.Cu")
		(net "M_C_CPU1_SA_DQS_DN<6>")
	)
	(arc
		(start 89.947496 -269.873222)
		(mid 89.664794 -269.948964)
		(end 89.382092 -269.873222)
		(width 0.088646)
		(layer "In6.Cu")
		(net "M_C_CPU1_SA_DQS_DN<6>")
	)
	(arc
		(start 95.021146 -269.873222)
		(mid 94.833948 -269.823079)
		(end 94.64675 -269.873222)
		(width 0.088646)
		(layer "In6.Cu")
		(net "M_C_CPU1_SA_DQS_DN<6>")
	)
	(arc
		(start 93.141546 -269.873222)
		(mid 92.954348 -269.823079)
		(end 92.76715 -269.873222)
		(width 0.088646)
		(layer "In6.Cu")
		(net "M_C_CPU1_SA_DQS_DN<6>")
	)
	(arc
		(start 85.709506 -270.692118)
		(mid 85.578592 -270.828478)
		(end 85.530944 -271.011396)
		(width 0.088646)
		(layer "In6.Cu")
		(net "M_C_CPU1_SA_DQS_DN<6>")
	)
	(arc
		(start 95.58655 -269.873222)
		(mid 95.312321 -269.949147)
		(end 95.035878 -269.881858)
		(width 0.088646)
		(layer "In6.Cu")
		(net "M_C_CPU1_SA_DQS_DN<6>")
	)
	(arc
		(start 96.900746 -270.521938)
		(mid 96.713548 -270.572081)
		(end 96.52635 -270.521938)
		(width 0.088646)
		(layer "In6.Cu")
		(net "M_C_CPU1_SA_DQS_DN<6>")
	)
	(arc
		(start 96.51746 -270.516858)
		(mid 96.386546 -270.380498)
		(end 96.338898 -270.19758)
		(width 0.088646)
		(layer "In6.Cu")
		(net "M_C_CPU1_SA_DQS_DN<6>")
	)
	(arc
		(start 87.119206 -269.878302)
		(mid 86.988292 -270.014662)
		(end 86.940644 -270.19758)
		(width 0.088646)
		(layer "In6.Cu")
		(net "M_C_CPU1_SA_DQS_DN<6>")
	)
	(arc
		(start 87.502492 -269.873222)
		(mid 87.315294 -269.823079)
		(end 87.128096 -269.873222)
		(width 0.088646)
		(layer "In6.Cu")
		(net "M_C_CPU1_SA_DQS_DN<6>")
	)
	(arc
		(start 88.067896 -269.873222)
		(mid 87.785194 -269.948964)
		(end 87.502492 -269.873222)
		(width 0.088646)
		(layer "In6.Cu")
		(net "M_C_CPU1_SA_DQS_DN<6>")
	)
	(arc
		(start 86.940644 -270.207486)
		(mid 86.862533 -270.484435)
		(end 86.658196 -270.687038)
		(width 0.088646)
		(layer "In6.Cu")
		(net "M_C_CPU1_SA_DQS_DN<6>")
	)
	(arc
		(start 89.007696 -269.873222)
		(mid 88.724994 -269.948964)
		(end 88.442292 -269.873222)
		(width 0.088646)
		(layer "In6.Cu")
		(net "M_C_CPU1_SA_DQS_DN<6>")
	)
	(arc
		(start 92.201492 -269.873222)
		(mid 92.014294 -269.823079)
		(end 91.827096 -269.873222)
		(width 0.088646)
		(layer "In6.Cu")
		(net "M_C_CPU1_SA_DQS_DN<6>")
	)
	(arc
		(start 90.88755 -269.873222)
		(mid 90.610737 -269.949058)
		(end 90.332306 -269.879318)
		(width 0.088646)
		(layer "In6.Cu")
		(net "M_C_CPU1_SA_DQS_DN<6>")
	)
	(arc
		(start 90.321892 -269.873222)
		(mid 90.134694 -269.823079)
		(end 89.947496 -269.873222)
		(width 0.088646)
		(layer "In6.Cu")
		(net "M_C_CPU1_SA_DQS_DN<6>")
	)
	(arc
		(start 91.816682 -269.879318)
		(mid 91.538504 -269.94901)
		(end 91.261946 -269.873222)
		(width 0.088646)
		(layer "In6.Cu")
		(net "M_C_CPU1_SA_DQS_DN<6>")
	)
	(arc
		(start 86.092792 -270.687038)
		(mid 85.905594 -270.636895)
		(end 85.718396 -270.687038)
		(width 0.088646)
		(layer "In6.Cu")
		(net "M_C_CPU1_SA_DQS_DN<6>")
	)
	(arc
		(start 94.64675 -269.873222)
		(mid 94.372521 -269.949147)
		(end 94.096078 -269.881858)
		(width 0.088646)
		(layer "In6.Cu")
		(net "M_C_CPU1_SA_DQS_DN<6>")
	)
	(arc
		(start 91.261946 -269.873222)
		(mid 91.074748 -269.823079)
		(end 90.88755 -269.873222)
		(width 0.088646)
		(layer "In6.Cu")
		(net "M_C_CPU1_SA_DQS_DN<6>")
	)
	(arc
		(start 86.658196 -270.687038)
		(mid 86.375494 -270.762814)
		(end 86.092792 -270.687038)
		(width 0.088646)
		(layer "In6.Cu")
		(net "M_C_CPU1_SA_DQS_DN<6>")
	)
	(arc
		(start 89.382092 -269.873222)
		(mid 89.194894 -269.823079)
		(end 89.007696 -269.873222)
		(width 0.088646)
		(layer "In6.Cu")
		(net "M_C_CPU1_SA_DQS_DN<6>")
	)
	(arc
		(start 95.960946 -269.873222)
		(mid 95.773748 -269.823079)
		(end 95.58655 -269.873222)
		(width 0.088646)
		(layer "In6.Cu")
		(net "M_C_CPU1_SA_DQS_DN<6>")
	)
	(arc
		(start 92.76715 -269.873222)
		(mid 92.490337 -269.949058)
		(end 92.211906 -269.879318)
		(width 0.088646)
		(layer "In6.Cu")
		(net "M_C_CPU1_SA_DQS_DN<6>")
	)
	(arc
		(start 93.70695 -269.873222)
		(mid 93.432721 -269.949147)
		(end 93.156278 -269.881858)
		(width 0.088646)
		(layer "In6.Cu")
		(net "M_C_CPU1_SA_DQS_DN<6>")
	)
	(segment
		(start 28.060904 -311.805574)
		(end 28.534106 -311.805574)
		(width 0.20066)
		(layer "F.Cu")
		(net "M_C_CPU1_SA_DQS_DN<5>")
	)
	(segment
		(start 31.972758 -311.641744)
		(end 32.114998 -311.641744)
		(width 0.20066)
		(layer "F.Cu")
		(net "M_C_CPU1_SA_DQS_DN<5>")
	)
	(segment
		(start 29.649166 -311.651396)
		(end 29.658818 -311.641744)
		(width 0.101854)
		(layer "F.Cu")
		(net "M_C_CPU1_SA_DQS_DN<5>")
	)
	(segment
		(start 29.196284 -311.383172)
		(end 29.464508 -311.651396)
		(width 0.20066)
		(layer "F.Cu")
		(net "M_C_CPU1_SA_DQS_DN<5>")
	)
	(segment
		(start 29.647642 -311.651396)
		(end 29.649166 -311.651396)
		(width 0.101854)
		(layer "F.Cu")
		(net "M_C_CPU1_SA_DQS_DN<5>")
	)
	(segment
		(start 29.464508 -311.651396)
		(end 29.647642 -311.651396)
		(width 0.20066)
		(layer "F.Cu")
		(net "M_C_CPU1_SA_DQS_DN<5>")
	)
	(segment
		(start 32.37611 -311.380632)
		(end 32.780732 -311.380632)
		(width 0.20066)
		(layer "F.Cu")
		(net "M_C_CPU1_SA_DQS_DN<5>")
	)
	(segment
		(start 28.956508 -311.383172)
		(end 29.196284 -311.383172)
		(width 0.20066)
		(layer "F.Cu")
		(net "M_C_CPU1_SA_DQS_DN<5>")
	)
	(segment
		(start 33.416748 -311.805574)
		(end 34.120328 -311.805574)
		(width 0.20066)
		(layer "F.Cu")
		(net "M_C_CPU1_SA_DQS_DN<5>")
	)
	(segment
		(start 29.895292 -311.641744)
		(end 31.972758 -311.641744)
		(width 0.1016)
		(layer "F.Cu")
		(net "M_C_CPU1_SA_DQS_DN<5>")
	)
	(segment
		(start 29.658818 -311.641744)
		(end 29.895292 -311.641744)
		(width 0.101854)
		(layer "F.Cu")
		(net "M_C_CPU1_SA_DQS_DN<5>")
	)
	(segment
		(start 34.38144 -312.066686)
		(end 34.871914 -312.066686)
		(width 0.20066)
		(layer "F.Cu")
		(net "M_C_CPU1_SA_DQS_DN<5>")
	)
	(segment
		(start 32.780732 -311.380632)
		(end 33.416748 -311.805574)
		(width 0.20066)
		(layer "F.Cu")
		(net "M_C_CPU1_SA_DQS_DN<5>")
	)
	(segment
		(start 35.976814 -312.066686)
		(end 34.871914 -312.066686)
		(width 0.20066)
		(layer "F.Cu")
		(net "M_C_CPU1_SA_DQS_DN<5>")
	)
	(segment
		(start 93.423994 -276.986746)
		(end 93.423994 -277.522432)
		(width 0.20066)
		(layer "F.Cu")
		(net "M_C_CPU1_SA_DQS_DN<5>")
	)
	(segment
		(start 32.114998 -311.641744)
		(end 32.37611 -311.380632)
		(width 0.20066)
		(layer "F.Cu")
		(net "M_C_CPU1_SA_DQS_DN<5>")
	)
	(segment
		(start 34.120328 -311.805574)
		(end 34.38144 -312.066686)
		(width 0.20066)
		(layer "F.Cu")
		(net "M_C_CPU1_SA_DQS_DN<5>")
	)
	(segment
		(start 93.424248 -276.986492)
		(end 93.423994 -276.986746)
		(width 0.20066)
		(layer "F.Cu")
		(net "M_C_CPU1_SA_DQS_DN<5>")
	)
	(segment
		(start 28.534106 -311.805574)
		(end 28.956508 -311.383172)
		(width 0.20066)
		(layer "F.Cu")
		(net "M_C_CPU1_SA_DQS_DN<5>")
	)
	(segment
		(start 27.328114 -312.066686)
		(end 27.799792 -312.066686)
		(width 0.20066)
		(layer "F.Cu")
		(net "M_C_CPU1_SA_DQS_DN<5>")
	)
	(segment
		(start 27.799792 -312.066686)
		(end 28.060904 -311.805574)
		(width 0.20066)
		(layer "F.Cu")
		(net "M_C_CPU1_SA_DQS_DN<5>")
	)
	(segment
		(start 92.296996 -277.198074)
		(end 92.282264 -277.20671)
		(width 0.088646)
		(layer "In4.Cu")
		(net "M_C_CPU1_SA_DQS_DN<5>")
	)
	(segment
		(start 84.74075 -284.808676)
		(end 84.74075 -284.893512)
		(width 0.088646)
		(layer "In4.Cu")
		(net "M_C_CPU1_SA_DQS_DN<5>")
	)
	(segment
		(start 89.477596 -278.82596)
		(end 89.468706 -278.83104)
		(width 0.088646)
		(layer "In4.Cu")
		(net "M_C_CPU1_SA_DQS_DN<5>")
	)
	(segment
		(start 56.516778 -311.730898)
		(end 55.179976 -313.0677)
		(width 0.18288)
		(layer "In4.Cu")
		(net "M_C_CPU1_SA_DQS_DN<5>")
	)
	(segment
		(start 90.41765 -277.198074)
		(end 90.416634 -277.198582)
		(width 0.088646)
		(layer "In4.Cu")
		(net "M_C_CPU1_SA_DQS_DN<5>")
	)
	(segment
		(start 61.37275 -310.918606)
		(end 60.82411 -310.918606)
		(width 0.18288)
		(layer "In4.Cu")
		(net "M_C_CPU1_SA_DQS_DN<5>")
	)
	(segment
		(start 60.82411 -310.918606)
		(end 60.69965 -310.794146)
		(width 0.18288)
		(layer "In4.Cu")
		(net "M_C_CPU1_SA_DQS_DN<5>")
	)
	(segment
		(start 87.982806 -282.087574)
		(end 87.972392 -282.081478)
		(width 0.088646)
		(layer "In4.Cu")
		(net "M_C_CPU1_SA_DQS_DN<5>")
	)
	(segment
		(start 62.745874 -310.794146)
		(end 61.49721 -310.794146)
		(width 0.18288)
		(layer "In4.Cu")
		(net "M_C_CPU1_SA_DQS_DN<5>")
	)
	(segment
		(start 89.760044 -278.336502)
		(end 89.760044 -278.346408)
		(width 0.088646)
		(layer "In4.Cu")
		(net "M_C_CPU1_SA_DQS_DN<5>")
	)
	(segment
		(start 70.893178 -303.89322)
		(end 70.893178 -305.036474)
		(width 0.18288)
		(layer "In4.Cu")
		(net "M_C_CPU1_SA_DQS_DN<5>")
	)
	(segment
		(start 51.509676 -313.0677)
		(end 51.23561 -313.341766)
		(width 0.18288)
		(layer "In4.Cu")
		(net "M_C_CPU1_SA_DQS_DN<5>")
	)
	(segment
		(start 59.379612 -310.794146)
		(end 59.07151 -311.101994)
		(width 0.18288)
		(layer "In4.Cu")
		(net "M_C_CPU1_SA_DQS_DN<5>")
	)
	(segment
		(start 70.893178 -305.036474)
		(end 64.726566 -311.203086)
		(width 0.18288)
		(layer "In4.Cu")
		(net "M_C_CPU1_SA_DQS_DN<5>")
	)
	(segment
		(start 88.998806 -280.283412)
		(end 89.007696 -280.288492)
		(width 0.088646)
		(layer "In4.Cu")
		(net "M_C_CPU1_SA_DQS_DN<5>")
	)
	(segment
		(start 41.165526 -312.127646)
		(end 36.841938 -312.127646)
		(width 0.18288)
		(layer "In4.Cu")
		(net "M_C_CPU1_SA_DQS_DN<5>")
	)
	(segment
		(start 93.236796 -277.198074)
		(end 93.222064 -277.20671)
		(width 0.088646)
		(layer "In4.Cu")
		(net "M_C_CPU1_SA_DQS_DN<5>")
	)
	(segment
		(start 89.006934 -281.26817)
		(end 89.003124 -281.270456)
		(width 0.088646)
		(layer "In4.Cu")
		(net "M_C_CPU1_SA_DQS_DN<5>")
	)
	(segment
		(start 89.290144 -280.759662)
		(end 89.290144 -280.793698)
		(width 0.088646)
		(layer "In4.Cu")
		(net "M_C_CPU1_SA_DQS_DN<5>")
	)
	(segment
		(start 60.69965 -310.794146)
		(end 59.379612 -310.794146)
		(width 0.18288)
		(layer "In4.Cu")
		(net "M_C_CPU1_SA_DQS_DN<5>")
	)
	(segment
		(start 93.736668 -277.522432)
		(end 93.794072 -277.465028)
		(width 0.088646)
		(layer "In4.Cu")
		(net "M_C_CPU1_SA_DQS_DN<5>")
	)
	(segment
		(start 46.487334 -313.908948)
		(end 45.890434 -313.908948)
		(width 0.18288)
		(layer "In4.Cu")
		(net "M_C_CPU1_SA_DQS_DN<5>")
	)
	(segment
		(start 81.74609 -287.888426)
		(end 78.101698 -296.684954)
		(width 0.18288)
		(layer "In4.Cu")
		(net "M_C_CPU1_SA_DQS_DN<5>")
	)
	(segment
		(start 57.55259 -311.730898)
		(end 56.516778 -311.730898)
		(width 0.18288)
		(layer "In4.Cu")
		(net "M_C_CPU1_SA_DQS_DN<5>")
	)
	(segment
		(start 90.230198 -277.522432)
		(end 90.230198 -277.530052)
		(width 0.088646)
		(layer "In4.Cu")
		(net "M_C_CPU1_SA_DQS_DN<5>")
	)
	(segment
		(start 87.410798 -282.3972)
		(end 87.410798 -282.42006)
		(width 0.088646)
		(layer "In4.Cu")
		(net "M_C_CPU1_SA_DQS_DN<5>")
	)
	(segment
		(start 46.77029 -314.191904)
		(end 46.487334 -313.908948)
		(width 0.18288)
		(layer "In4.Cu")
		(net "M_C_CPU1_SA_DQS_DN<5>")
	)
	(segment
		(start 50.585116 -313.056016)
		(end 49.918366 -313.056016)
		(width 0.18288)
		(layer "In4.Cu")
		(net "M_C_CPU1_SA_DQS_DN<5>")
	)
	(segment
		(start 47.135542 -314.191904)
		(end 46.77029 -314.191904)
		(width 0.18288)
		(layer "In4.Cu")
		(net "M_C_CPU1_SA_DQS_DN<5>")
	)
	(segment
		(start 41.450006 -312.412126)
		(end 41.165526 -312.127646)
		(width 0.18288)
		(layer "In4.Cu")
		(net "M_C_CPU1_SA_DQS_DN<5>")
	)
	(segment
		(start 85.043518 -284.326838)
		(end 84.916772 -284.632654)
		(width 0.088646)
		(layer "In4.Cu")
		(net "M_C_CPU1_SA_DQS_DN<5>")
	)
	(segment
		(start 50.870866 -313.341766)
		(end 50.585116 -313.056016)
		(width 0.18288)
		(layer "In4.Cu")
		(net "M_C_CPU1_SA_DQS_DN<5>")
	)
	(segment
		(start 89.947496 -278.012144)
		(end 89.938606 -278.017224)
		(width 0.088646)
		(layer "In4.Cu")
		(net "M_C_CPU1_SA_DQS_DN<5>")
	)
	(segment
		(start 89.007696 -279.639776)
		(end 88.998806 -279.644856)
		(width 0.088646)
		(layer "In4.Cu")
		(net "M_C_CPU1_SA_DQS_DN<5>")
	)
	(segment
		(start 36.249356 -311.794144)
		(end 35.976814 -312.066686)
		(width 0.18288)
		(layer "In4.Cu")
		(net "M_C_CPU1_SA_DQS_DN<5>")
	)
	(segment
		(start 45.890434 -313.908948)
		(end 45.05198 -313.070494)
		(width 0.18288)
		(layer "In4.Cu")
		(net "M_C_CPU1_SA_DQS_DN<5>")
	)
	(segment
		(start 89.290144 -279.150318)
		(end 89.290144 -279.160224)
		(width 0.088646)
		(layer "In4.Cu")
		(net "M_C_CPU1_SA_DQS_DN<5>")
	)
	(segment
		(start 89.003124 -281.270456)
		(end 88.99906 -281.272742)
		(width 0.088646)
		(layer "In4.Cu")
		(net "M_C_CPU1_SA_DQS_DN<5>")
	)
	(segment
		(start 59.07151 -311.101994)
		(end 57.55259 -311.730898)
		(width 0.18288)
		(layer "In4.Cu")
		(net "M_C_CPU1_SA_DQS_DN<5>")
	)
	(segment
		(start 78.101698 -296.684954)
		(end 70.893178 -303.89322)
		(width 0.18288)
		(layer "In4.Cu")
		(net "M_C_CPU1_SA_DQS_DN<5>")
	)
	(segment
		(start 84.712556 -284.921706)
		(end 81.74609 -287.888426)
		(width 0.18288)
		(layer "In4.Cu")
		(net "M_C_CPU1_SA_DQS_DN<5>")
	)
	(segment
		(start 47.398432 -313.929014)
		(end 47.135542 -314.191904)
		(width 0.18288)
		(layer "In4.Cu")
		(net "M_C_CPU1_SA_DQS_DN<5>")
	)
	(segment
		(start 45.05198 -313.070494)
		(end 44.600368 -313.070494)
		(width 0.18288)
		(layer "In4.Cu")
		(net "M_C_CPU1_SA_DQS_DN<5>")
	)
	(segment
		(start 89.00795 -281.267662)
		(end 89.006934 -281.26817)
		(width 0.088646)
		(layer "In4.Cu")
		(net "M_C_CPU1_SA_DQS_DN<5>")
	)
	(segment
		(start 49.045368 -313.929014)
		(end 47.398432 -313.929014)
		(width 0.18288)
		(layer "In4.Cu")
		(net "M_C_CPU1_SA_DQS_DN<5>")
	)
	(segment
		(start 93.423994 -277.522432)
		(end 93.736668 -277.522432)
		(width 0.088646)
		(layer "In4.Cu")
		(net "M_C_CPU1_SA_DQS_DN<5>")
	)
	(segment
		(start 90.80246 -277.20417)
		(end 90.792046 -277.198074)
		(width 0.088646)
		(layer "In4.Cu")
		(net "M_C_CPU1_SA_DQS_DN<5>")
	)
	(segment
		(start 49.918366 -313.056016)
		(end 49.045368 -313.929014)
		(width 0.18288)
		(layer "In4.Cu")
		(net "M_C_CPU1_SA_DQS_DN<5>")
	)
	(segment
		(start 36.508436 -311.794144)
		(end 36.249356 -311.794144)
		(width 0.18288)
		(layer "In4.Cu")
		(net "M_C_CPU1_SA_DQS_DN<5>")
	)
	(segment
		(start 90.416634 -277.198582)
		(end 90.40876 -277.203154)
		(width 0.088646)
		(layer "In4.Cu")
		(net "M_C_CPU1_SA_DQS_DN<5>")
	)
	(segment
		(start 51.23561 -313.341766)
		(end 50.870866 -313.341766)
		(width 0.18288)
		(layer "In4.Cu")
		(net "M_C_CPU1_SA_DQS_DN<5>")
	)
	(segment
		(start 64.726566 -311.203086)
		(end 63.154814 -311.203086)
		(width 0.18288)
		(layer "In4.Cu")
		(net "M_C_CPU1_SA_DQS_DN<5>")
	)
	(segment
		(start 84.74075 -284.893512)
		(end 84.712556 -284.921706)
		(width 0.088646)
		(layer "In4.Cu")
		(net "M_C_CPU1_SA_DQS_DN<5>")
	)
	(segment
		(start 63.154814 -311.203086)
		(end 62.745874 -310.794146)
		(width 0.18288)
		(layer "In4.Cu")
		(net "M_C_CPU1_SA_DQS_DN<5>")
	)
	(segment
		(start 85.475064 -283.895038)
		(end 85.043518 -284.326838)
		(width 0.088646)
		(layer "In4.Cu")
		(net "M_C_CPU1_SA_DQS_DN<5>")
	)
	(segment
		(start 86.000844 -283.219906)
		(end 86.000844 -283.229812)
		(width 0.088646)
		(layer "In4.Cu")
		(net "M_C_CPU1_SA_DQS_DN<5>")
	)
	(segment
		(start 43.942 -312.412126)
		(end 41.450006 -312.412126)
		(width 0.18288)
		(layer "In4.Cu")
		(net "M_C_CPU1_SA_DQS_DN<5>")
	)
	(segment
		(start 44.600368 -313.070494)
		(end 43.942 -312.412126)
		(width 0.18288)
		(layer "In4.Cu")
		(net "M_C_CPU1_SA_DQS_DN<5>")
	)
	(segment
		(start 84.916772 -284.632654)
		(end 84.74075 -284.808676)
		(width 0.088646)
		(layer "In4.Cu")
		(net "M_C_CPU1_SA_DQS_DN<5>")
	)
	(segment
		(start 36.841938 -312.127646)
		(end 36.508436 -311.794144)
		(width 0.18288)
		(layer "In4.Cu")
		(net "M_C_CPU1_SA_DQS_DN<5>")
	)
	(segment
		(start 61.49721 -310.794146)
		(end 61.37275 -310.918606)
		(width 0.18288)
		(layer "In4.Cu")
		(net "M_C_CPU1_SA_DQS_DN<5>")
	)
	(segment
		(start 55.179976 -313.0677)
		(end 51.509676 -313.0677)
		(width 0.18288)
		(layer "In4.Cu")
		(net "M_C_CPU1_SA_DQS_DN<5>")
	)
	(arc
		(start 90.792046 -277.198074)
		(mid 90.604848 -277.147931)
		(end 90.41765 -277.198074)
		(width 0.088646)
		(layer "In4.Cu")
		(net "M_C_CPU1_SA_DQS_DN<5>")
	)
	(arc
		(start 89.468706 -278.83104)
		(mid 89.337792 -278.9674)
		(end 89.290144 -279.150318)
		(width 0.088646)
		(layer "In4.Cu")
		(net "M_C_CPU1_SA_DQS_DN<5>")
	)
	(arc
		(start 90.40876 -277.203154)
		(mid 90.277846 -277.339514)
		(end 90.230198 -277.522432)
		(width 0.088646)
		(layer "In4.Cu")
		(net "M_C_CPU1_SA_DQS_DN<5>")
	)
	(arc
		(start 87.972392 -282.081478)
		(mid 87.601669 -282.079386)
		(end 87.410798 -282.3972)
		(width 0.088646)
		(layer "In4.Cu")
		(net "M_C_CPU1_SA_DQS_DN<5>")
	)
	(arc
		(start 91.357196 -277.198074)
		(mid 91.080637 -277.273817)
		(end 90.80246 -277.20417)
		(width 0.088646)
		(layer "In4.Cu")
		(net "M_C_CPU1_SA_DQS_DN<5>")
	)
	(arc
		(start 93.794072 -277.465028)
		(mid 93.58575 -277.184874)
		(end 93.236796 -277.198074)
		(width 0.088646)
		(layer "In4.Cu")
		(net "M_C_CPU1_SA_DQS_DN<5>")
	)
	(arc
		(start 92.671392 -277.198074)
		(mid 92.484194 -277.147931)
		(end 92.296996 -277.198074)
		(width 0.088646)
		(layer "In4.Cu")
		(net "M_C_CPU1_SA_DQS_DN<5>")
	)
	(arc
		(start 85.718396 -283.709364)
		(mid 85.590516 -283.794057)
		(end 85.475064 -283.895038)
		(width 0.088646)
		(layer "In4.Cu")
		(net "M_C_CPU1_SA_DQS_DN<5>")
	)
	(arc
		(start 90.230198 -277.530052)
		(mid 90.152569 -277.808465)
		(end 89.947496 -278.012144)
		(width 0.088646)
		(layer "In4.Cu")
		(net "M_C_CPU1_SA_DQS_DN<5>")
	)
	(arc
		(start 92.282264 -277.20671)
		(mid 92.005789 -277.27403)
		(end 91.731592 -277.198074)
		(width 0.088646)
		(layer "In4.Cu")
		(net "M_C_CPU1_SA_DQS_DN<5>")
	)
	(arc
		(start 89.938606 -278.017224)
		(mid 89.807692 -278.153584)
		(end 89.760044 -278.336502)
		(width 0.088646)
		(layer "In4.Cu")
		(net "M_C_CPU1_SA_DQS_DN<5>")
	)
	(arc
		(start 86.562692 -282.895548)
		(mid 86.188217 -282.895594)
		(end 86.000844 -283.219906)
		(width 0.088646)
		(layer "In4.Cu")
		(net "M_C_CPU1_SA_DQS_DN<5>")
	)
	(arc
		(start 89.290144 -279.160224)
		(mid 89.212033 -279.437173)
		(end 89.007696 -279.639776)
		(width 0.088646)
		(layer "In4.Cu")
		(net "M_C_CPU1_SA_DQS_DN<5>")
	)
	(arc
		(start 91.731592 -277.198074)
		(mid 91.544394 -277.147931)
		(end 91.357196 -277.198074)
		(width 0.088646)
		(layer "In4.Cu")
		(net "M_C_CPU1_SA_DQS_DN<5>")
	)
	(arc
		(start 87.410798 -282.42006)
		(mid 87.122099 -282.899207)
		(end 86.562692 -282.895548)
		(width 0.088646)
		(layer "In4.Cu")
		(net "M_C_CPU1_SA_DQS_DN<5>")
	)
	(arc
		(start 89.290144 -280.793698)
		(mid 89.210774 -281.067432)
		(end 89.00795 -281.267662)
		(width 0.088646)
		(layer "In4.Cu")
		(net "M_C_CPU1_SA_DQS_DN<5>")
	)
	(arc
		(start 88.99906 -281.272742)
		(mid 88.868146 -281.409102)
		(end 88.820498 -281.59202)
		(width 0.088646)
		(layer "In4.Cu")
		(net "M_C_CPU1_SA_DQS_DN<5>")
	)
	(arc
		(start 88.820498 -281.59202)
		(mid 88.542963 -282.078655)
		(end 87.982806 -282.087574)
		(width 0.088646)
		(layer "In4.Cu")
		(net "M_C_CPU1_SA_DQS_DN<5>")
	)
	(arc
		(start 88.998806 -279.644856)
		(mid 88.820209 -279.964134)
		(end 88.998806 -280.283412)
		(width 0.088646)
		(layer "In4.Cu")
		(net "M_C_CPU1_SA_DQS_DN<5>")
	)
	(arc
		(start 89.007696 -280.288492)
		(mid 89.209982 -280.487473)
		(end 89.290144 -280.759662)
		(width 0.088646)
		(layer "In4.Cu")
		(net "M_C_CPU1_SA_DQS_DN<5>")
	)
	(arc
		(start 86.000844 -283.229812)
		(mid 85.922733 -283.506761)
		(end 85.718396 -283.709364)
		(width 0.088646)
		(layer "In4.Cu")
		(net "M_C_CPU1_SA_DQS_DN<5>")
	)
	(arc
		(start 93.222064 -277.20671)
		(mid 92.945589 -277.27403)
		(end 92.671392 -277.198074)
		(width 0.088646)
		(layer "In4.Cu")
		(net "M_C_CPU1_SA_DQS_DN<5>")
	)
	(arc
		(start 89.760044 -278.346408)
		(mid 89.681933 -278.623357)
		(end 89.477596 -278.82596)
		(width 0.088646)
		(layer "In4.Cu")
		(net "M_C_CPU1_SA_DQS_DN<5>")
	)
	(segment
		(start 28.945586 -275.353018)
		(end 29.132276 -275.353018)
		(width 0.20066)
		(layer "F.Cu")
		(net "M_C_CPU1_SA_DQS_DN<4>")
	)
	(segment
		(start 25.989026 -275.091652)
		(end 26.074116 -275.091652)
		(width 0.20066)
		(layer "F.Cu")
		(net "M_C_CPU1_SA_DQS_DN<4>")
	)
	(segment
		(start 26.074116 -275.091652)
		(end 26.21534 -275.091652)
		(width 0.101854)
		(layer "F.Cu")
		(net "M_C_CPU1_SA_DQS_DN<4>")
	)
	(segment
		(start 30.225238 -274.66671)
		(end 30.771846 -274.66671)
		(width 0.20066)
		(layer "F.Cu")
		(net "M_C_CPU1_SA_DQS_DN<4>")
	)
	(segment
		(start 29.557472 -274.927822)
		(end 29.964126 -274.927822)
		(width 0.20066)
		(layer "F.Cu")
		(net "M_C_CPU1_SA_DQS_DN<4>")
	)
	(segment
		(start 31.876746 -274.66671)
		(end 30.771846 -274.66671)
		(width 0.20066)
		(layer "F.Cu")
		(net "M_C_CPU1_SA_DQS_DN<4>")
	)
	(segment
		(start 28.594812 -275.091652)
		(end 28.68422 -275.091652)
		(width 0.20066)
		(layer "F.Cu")
		(net "M_C_CPU1_SA_DQS_DN<4>")
	)
	(segment
		(start 28.529026 -275.091652)
		(end 28.594812 -275.091652)
		(width 0.101854)
		(layer "F.Cu")
		(net "M_C_CPU1_SA_DQS_DN<4>")
	)
	(segment
		(start 24.55164 -274.927822)
		(end 25.187656 -275.353018)
		(width 0.20066)
		(layer "F.Cu")
		(net "M_C_CPU1_SA_DQS_DN<4>")
	)
	(segment
		(start 26.21534 -275.091652)
		(end 28.529026 -275.091652)
		(width 0.1016)
		(layer "F.Cu")
		(net "M_C_CPU1_SA_DQS_DN<4>")
	)
	(segment
		(start 29.132276 -275.353018)
		(end 29.557472 -274.927822)
		(width 0.20066)
		(layer "F.Cu")
		(net "M_C_CPU1_SA_DQS_DN<4>")
	)
	(segment
		(start 23.228046 -274.66671)
		(end 23.776686 -274.66671)
		(width 0.20066)
		(layer "F.Cu")
		(net "M_C_CPU1_SA_DQS_DN<4>")
	)
	(segment
		(start 28.68422 -275.091652)
		(end 28.945586 -275.353018)
		(width 0.20066)
		(layer "F.Cu")
		(net "M_C_CPU1_SA_DQS_DN<4>")
	)
	(segment
		(start 25.187656 -275.353018)
		(end 25.72766 -275.353018)
		(width 0.20066)
		(layer "F.Cu")
		(net "M_C_CPU1_SA_DQS_DN<4>")
	)
	(segment
		(start 24.037798 -274.927822)
		(end 24.55164 -274.927822)
		(width 0.20066)
		(layer "F.Cu")
		(net "M_C_CPU1_SA_DQS_DN<4>")
	)
	(segment
		(start 25.72766 -275.353018)
		(end 25.989026 -275.091652)
		(width 0.20066)
		(layer "F.Cu")
		(net "M_C_CPU1_SA_DQS_DN<4>")
	)
	(segment
		(start 23.776686 -274.66671)
		(end 24.037798 -274.927822)
		(width 0.20066)
		(layer "F.Cu")
		(net "M_C_CPU1_SA_DQS_DN<4>")
	)
	(segment
		(start 29.964126 -274.927822)
		(end 30.225238 -274.66671)
		(width 0.20066)
		(layer "F.Cu")
		(net "M_C_CPU1_SA_DQS_DN<4>")
	)
	(segment
		(start 95.773494 -259.894832)
		(end 95.773748 -260.430772)
		(width 0.20066)
		(layer "F.Cu")
		(net "M_C_CPU1_SA_DQS_DN<4>")
	)
	(segment
		(start 56.240426 -265.381486)
		(end 54.730396 -266.006834)
		(width 0.18288)
		(layer "In6.Cu")
		(net "M_C_CPU1_SA_DQS_DN<4>")
	)
	(segment
		(start 84.096352 -260.030468)
		(end 83.99399 -260.131814)
		(width 0.088646)
		(layer "In6.Cu")
		(net "M_C_CPU1_SA_DQS_DN<4>")
	)
	(segment
		(start 47.24654 -266.592812)
		(end 47.09922 -266.592812)
		(width 0.18288)
		(layer "In6.Cu")
		(net "M_C_CPU1_SA_DQS_DN<4>")
	)
	(segment
		(start 64.534034 -264.7442)
		(end 64.165226 -264.896346)
		(width 0.18288)
		(layer "In6.Cu")
		(net "M_C_CPU1_SA_DQS_DN<4>")
	)
	(segment
		(start 82.65795 -260.772148)
		(end 81.273396 -260.772148)
		(width 0.18288)
		(layer "In6.Cu")
		(net "M_C_CPU1_SA_DQS_DN<4>")
	)
	(segment
		(start 50.581052 -265.997182)
		(end 49.785524 -265.997182)
		(width 0.18288)
		(layer "In6.Cu")
		(net "M_C_CPU1_SA_DQS_DN<4>")
	)
	(segment
		(start 83.12023 -260.832092)
		(end 82.741262 -260.832092)
		(width 0.088646)
		(layer "In6.Cu")
		(net "M_C_CPU1_SA_DQS_DN<4>")
	)
	(segment
		(start 47.09922 -266.592812)
		(end 47.098966 -266.592558)
		(width 0.18288)
		(layer "In6.Cu")
		(net "M_C_CPU1_SA_DQS_DN<4>")
	)
	(segment
		(start 89.477596 -259.941314)
		(end 89.462864 -259.932678)
		(width 0.088646)
		(layer "In6.Cu")
		(net "M_C_CPU1_SA_DQS_DN<4>")
	)
	(segment
		(start 90.417396 -259.941314)
		(end 90.402664 -259.932678)
		(width 0.088646)
		(layer "In6.Cu")
		(net "M_C_CPU1_SA_DQS_DN<4>")
	)
	(segment
		(start 32.144462 -274.934426)
		(end 31.876746 -274.66671)
		(width 0.18288)
		(layer "In6.Cu")
		(net "M_C_CPU1_SA_DQS_DN<4>")
	)
	(segment
		(start 83.99399 -260.131814)
		(end 83.820508 -260.131814)
		(width 0.088646)
		(layer "In6.Cu")
		(net "M_C_CPU1_SA_DQS_DN<4>")
	)
	(segment
		(start 82.741262 -260.832092)
		(end 82.681318 -260.772148)
		(width 0.088646)
		(layer "In6.Cu")
		(net "M_C_CPU1_SA_DQS_DN<4>")
	)
	(segment
		(start 95.43288 -260.340856)
		(end 95.007684 -260.099048)
		(width 0.088646)
		(layer "In6.Cu")
		(net "M_C_CPU1_SA_DQS_DN<4>")
	)
	(segment
		(start 94.385638 -260.06171)
		(end 94.162118 -259.932932)
		(width 0.088646)
		(layer "In6.Cu")
		(net "M_C_CPU1_SA_DQS_DN<4>")
	)
	(segment
		(start 48.937418 -266.845288)
		(end 47.499016 -266.845288)
		(width 0.18288)
		(layer "In6.Cu")
		(net "M_C_CPU1_SA_DQS_DN<4>")
	)
	(segment
		(start 65.303654 -263.974326)
		(end 64.534034 -264.7442)
		(width 0.18288)
		(layer "In6.Cu")
		(net "M_C_CPU1_SA_DQS_DN<4>")
	)
	(segment
		(start 46.885352 -266.592812)
		(end 46.735492 -266.592812)
		(width 0.18288)
		(layer "In6.Cu")
		(net "M_C_CPU1_SA_DQS_DN<4>")
	)
	(segment
		(start 46.49216 -266.836144)
		(end 46.00321 -266.836144)
		(width 0.18288)
		(layer "In6.Cu")
		(net "M_C_CPU1_SA_DQS_DN<4>")
	)
	(segment
		(start 94.746064 -260.06425)
		(end 94.741238 -260.06171)
		(width 0.088646)
		(layer "In6.Cu")
		(net "M_C_CPU1_SA_DQS_DN<4>")
	)
	(segment
		(start 49.785524 -265.997182)
		(end 48.937418 -266.845288)
		(width 0.18288)
		(layer "In6.Cu")
		(net "M_C_CPU1_SA_DQS_DN<4>")
	)
	(segment
		(start 50.974752 -265.742674)
		(end 50.83556 -265.742674)
		(width 0.18288)
		(layer "In6.Cu")
		(net "M_C_CPU1_SA_DQS_DN<4>")
	)
	(segment
		(start 64.165226 -264.896346)
		(end 63.359538 -264.896346)
		(width 0.18288)
		(layer "In6.Cu")
		(net "M_C_CPU1_SA_DQS_DN<4>")
	)
	(segment
		(start 37.03193 -272.828766)
		(end 36.507166 -272.828766)
		(width 0.18288)
		(layer "In6.Cu")
		(net "M_C_CPU1_SA_DQS_DN<4>")
	)
	(segment
		(start 39.050214 -271.246092)
		(end 37.775388 -272.520664)
		(width 0.18288)
		(layer "In6.Cu")
		(net "M_C_CPU1_SA_DQS_DN<4>")
	)
	(segment
		(start 63.359538 -264.896346)
		(end 62.50051 -264.540746)
		(width 0.18288)
		(layer "In6.Cu")
		(net "M_C_CPU1_SA_DQS_DN<4>")
	)
	(segment
		(start 46.885606 -266.592558)
		(end 46.885352 -266.592812)
		(width 0.18288)
		(layer "In6.Cu")
		(net "M_C_CPU1_SA_DQS_DN<4>")
	)
	(segment
		(start 35.74669 -272.542508)
		(end 35.495992 -272.793206)
		(width 0.18288)
		(layer "In6.Cu")
		(net "M_C_CPU1_SA_DQS_DN<4>")
	)
	(segment
		(start 47.098966 -266.592558)
		(end 46.885606 -266.592558)
		(width 0.18288)
		(layer "In6.Cu")
		(net "M_C_CPU1_SA_DQS_DN<4>")
	)
	(segment
		(start 50.83556 -265.742674)
		(end 50.581052 -265.997182)
		(width 0.18288)
		(layer "In6.Cu")
		(net "M_C_CPU1_SA_DQS_DN<4>")
	)
	(segment
		(start 62.50051 -264.540746)
		(end 61.862208 -264.540746)
		(width 0.18288)
		(layer "In6.Cu")
		(net "M_C_CPU1_SA_DQS_DN<4>")
	)
	(segment
		(start 35.495992 -272.793206)
		(end 34.984436 -272.793206)
		(width 0.18288)
		(layer "In6.Cu")
		(net "M_C_CPU1_SA_DQS_DN<4>")
	)
	(segment
		(start 36.507166 -272.828766)
		(end 36.220908 -272.542508)
		(width 0.18288)
		(layer "In6.Cu")
		(net "M_C_CPU1_SA_DQS_DN<4>")
	)
	(segment
		(start 69.921628 -262.065516)
		(end 65.303654 -263.974326)
		(width 0.18288)
		(layer "In6.Cu")
		(net "M_C_CPU1_SA_DQS_DN<4>")
	)
	(segment
		(start 46.735492 -266.592812)
		(end 46.49216 -266.836144)
		(width 0.18288)
		(layer "In6.Cu")
		(net "M_C_CPU1_SA_DQS_DN<4>")
	)
	(segment
		(start 51.346608 -265.742674)
		(end 51.216306 -265.74242)
		(width 0.18288)
		(layer "In6.Cu")
		(net "M_C_CPU1_SA_DQS_DN<4>")
	)
	(segment
		(start 94.741238 -260.06171)
		(end 94.385638 -260.06171)
		(width 0.088646)
		(layer "In6.Cu")
		(net "M_C_CPU1_SA_DQS_DN<4>")
	)
	(segment
		(start 60.150502 -265.785346)
		(end 59.796934 -265.785346)
		(width 0.18288)
		(layer "In6.Cu")
		(net "M_C_CPU1_SA_DQS_DN<4>")
	)
	(segment
		(start 91.74226 -259.935218)
		(end 91.731846 -259.941314)
		(width 0.088646)
		(layer "In6.Cu")
		(net "M_C_CPU1_SA_DQS_DN<4>")
	)
	(segment
		(start 37.775388 -272.520664)
		(end 37.03193 -272.828766)
		(width 0.18288)
		(layer "In6.Cu")
		(net "M_C_CPU1_SA_DQS_DN<4>")
	)
	(segment
		(start 32.843216 -274.934426)
		(end 32.144462 -274.934426)
		(width 0.18288)
		(layer "In6.Cu")
		(net "M_C_CPU1_SA_DQS_DN<4>")
	)
	(segment
		(start 82.681318 -260.772148)
		(end 82.65795 -260.772148)
		(width 0.088646)
		(layer "In6.Cu")
		(net "M_C_CPU1_SA_DQS_DN<4>")
	)
	(segment
		(start 50.975006 -265.74242)
		(end 50.974752 -265.742674)
		(width 0.18288)
		(layer "In6.Cu")
		(net "M_C_CPU1_SA_DQS_DN<4>")
	)
	(segment
		(start 54.730396 -266.006834)
		(end 51.610768 -266.006834)
		(width 0.18288)
		(layer "In6.Cu")
		(net "M_C_CPU1_SA_DQS_DN<4>")
	)
	(segment
		(start 61.862208 -264.540746)
		(end 61.064648 -264.870946)
		(width 0.18288)
		(layer "In6.Cu")
		(net "M_C_CPU1_SA_DQS_DN<4>")
	)
	(segment
		(start 93.236796 -259.941314)
		(end 93.222064 -259.932678)
		(width 0.088646)
		(layer "In6.Cu")
		(net "M_C_CPU1_SA_DQS_DN<4>")
	)
	(segment
		(start 83.820508 -260.131814)
		(end 83.12023 -260.832092)
		(width 0.088646)
		(layer "In6.Cu")
		(net "M_C_CPU1_SA_DQS_DN<4>")
	)
	(segment
		(start 46.00321 -266.836144)
		(end 43.39082 -268.581886)
		(width 0.18288)
		(layer "In6.Cu")
		(net "M_C_CPU1_SA_DQS_DN<4>")
	)
	(segment
		(start 61.064648 -264.870946)
		(end 60.150502 -265.785346)
		(width 0.18288)
		(layer "In6.Cu")
		(net "M_C_CPU1_SA_DQS_DN<4>")
	)
	(segment
		(start 58.82259 -265.381486)
		(end 56.240426 -265.381486)
		(width 0.18288)
		(layer "In6.Cu")
		(net "M_C_CPU1_SA_DQS_DN<4>")
	)
	(segment
		(start 41.911778 -270.060674)
		(end 39.050214 -271.246092)
		(width 0.18288)
		(layer "In6.Cu")
		(net "M_C_CPU1_SA_DQS_DN<4>")
	)
	(segment
		(start 93.610938 -259.941314)
		(end 93.611192 -259.941314)
		(width 0.088646)
		(layer "In6.Cu")
		(net "M_C_CPU1_SA_DQS_DN<4>")
	)
	(segment
		(start 81.273396 -260.772148)
		(end 78.150466 -262.065516)
		(width 0.18288)
		(layer "In6.Cu")
		(net "M_C_CPU1_SA_DQS_DN<4>")
	)
	(segment
		(start 51.610768 -266.006834)
		(end 51.346608 -265.742674)
		(width 0.18288)
		(layer "In6.Cu")
		(net "M_C_CPU1_SA_DQS_DN<4>")
	)
	(segment
		(start 34.984436 -272.793206)
		(end 32.843216 -274.934426)
		(width 0.18288)
		(layer "In6.Cu")
		(net "M_C_CPU1_SA_DQS_DN<4>")
	)
	(segment
		(start 51.216306 -265.74242)
		(end 50.975006 -265.74242)
		(width 0.18288)
		(layer "In6.Cu")
		(net "M_C_CPU1_SA_DQS_DN<4>")
	)
	(segment
		(start 59.796934 -265.785346)
		(end 58.82259 -265.381486)
		(width 0.18288)
		(layer "In6.Cu")
		(net "M_C_CPU1_SA_DQS_DN<4>")
	)
	(segment
		(start 36.220908 -272.542508)
		(end 35.74669 -272.542508)
		(width 0.18288)
		(layer "In6.Cu")
		(net "M_C_CPU1_SA_DQS_DN<4>")
	)
	(segment
		(start 78.150466 -262.065516)
		(end 69.921628 -262.065516)
		(width 0.18288)
		(layer "In6.Cu")
		(net "M_C_CPU1_SA_DQS_DN<4>")
	)
	(segment
		(start 43.39082 -268.581886)
		(end 41.911778 -270.060674)
		(width 0.18288)
		(layer "In6.Cu")
		(net "M_C_CPU1_SA_DQS_DN<4>")
	)
	(segment
		(start 94.803214 -260.057392)
		(end 94.746064 -260.06425)
		(width 0.088646)
		(layer "In6.Cu")
		(net "M_C_CPU1_SA_DQS_DN<4>")
	)
	(segment
		(start 47.499016 -266.845288)
		(end 47.24654 -266.592812)
		(width 0.18288)
		(layer "In6.Cu")
		(net "M_C_CPU1_SA_DQS_DN<4>")
	)
	(segment
		(start 91.35745 -259.941314)
		(end 91.347036 -259.935218)
		(width 0.088646)
		(layer "In6.Cu")
		(net "M_C_CPU1_SA_DQS_DN<4>")
	)
	(arc
		(start 89.462864 -259.932678)
		(mid 89.186389 -259.865358)
		(end 88.912192 -259.941314)
		(width 0.088646)
		(layer "In6.Cu")
		(net "M_C_CPU1_SA_DQS_DN<4>")
	)
	(arc
		(start 87.972392 -259.941314)
		(mid 87.785194 -259.991457)
		(end 87.597996 -259.941314)
		(width 0.088646)
		(layer "In6.Cu")
		(net "M_C_CPU1_SA_DQS_DN<4>")
	)
	(arc
		(start 95.773748 -260.430772)
		(mid 95.597483 -260.407917)
		(end 95.43288 -260.340856)
		(width 0.088646)
		(layer "In6.Cu")
		(net "M_C_CPU1_SA_DQS_DN<4>")
	)
	(arc
		(start 95.007684 -260.099048)
		(mid 94.908842 -260.061538)
		(end 94.803214 -260.057392)
		(width 0.088646)
		(layer "In6.Cu")
		(net "M_C_CPU1_SA_DQS_DN<4>")
	)
	(arc
		(start 86.092792 -259.941314)
		(mid 85.905594 -259.991457)
		(end 85.718396 -259.941314)
		(width 0.088646)
		(layer "In6.Cu")
		(net "M_C_CPU1_SA_DQS_DN<4>")
	)
	(arc
		(start 87.032592 -259.941314)
		(mid 86.845394 -259.991457)
		(end 86.658196 -259.941314)
		(width 0.088646)
		(layer "In6.Cu")
		(net "M_C_CPU1_SA_DQS_DN<4>")
	)
	(arc
		(start 93.611192 -259.941314)
		(mid 93.423994 -259.991457)
		(end 93.236796 -259.941314)
		(width 0.088646)
		(layer "In6.Cu")
		(net "M_C_CPU1_SA_DQS_DN<4>")
	)
	(arc
		(start 85.152992 -259.941314)
		(mid 84.965794 -259.991457)
		(end 84.778596 -259.941314)
		(width 0.088646)
		(layer "In6.Cu")
		(net "M_C_CPU1_SA_DQS_DN<4>")
	)
	(arc
		(start 84.14893 -259.984494)
		(mid 84.121931 -260.006669)
		(end 84.096352 -260.030468)
		(width 0.088646)
		(layer "In6.Cu")
		(net "M_C_CPU1_SA_DQS_DN<4>")
	)
	(arc
		(start 92.296996 -259.941314)
		(mid 92.020437 -259.865571)
		(end 91.74226 -259.935218)
		(width 0.088646)
		(layer "In6.Cu")
		(net "M_C_CPU1_SA_DQS_DN<4>")
	)
	(arc
		(start 87.597996 -259.941314)
		(mid 87.315294 -259.865538)
		(end 87.032592 -259.941314)
		(width 0.088646)
		(layer "In6.Cu")
		(net "M_C_CPU1_SA_DQS_DN<4>")
	)
	(arc
		(start 88.912192 -259.941314)
		(mid 88.724994 -259.991457)
		(end 88.537796 -259.941314)
		(width 0.088646)
		(layer "In6.Cu")
		(net "M_C_CPU1_SA_DQS_DN<4>")
	)
	(arc
		(start 86.658196 -259.941314)
		(mid 86.375494 -259.865538)
		(end 86.092792 -259.941314)
		(width 0.088646)
		(layer "In6.Cu")
		(net "M_C_CPU1_SA_DQS_DN<4>")
	)
	(arc
		(start 94.162118 -259.932932)
		(mid 93.885453 -259.865461)
		(end 93.610938 -259.941314)
		(width 0.088646)
		(layer "In6.Cu")
		(net "M_C_CPU1_SA_DQS_DN<4>")
	)
	(arc
		(start 84.213192 -259.941314)
		(mid 84.180322 -259.961804)
		(end 84.14893 -259.984494)
		(width 0.088646)
		(layer "In6.Cu")
		(net "M_C_CPU1_SA_DQS_DN<4>")
	)
	(arc
		(start 90.402664 -259.932678)
		(mid 90.126189 -259.865358)
		(end 89.851992 -259.941314)
		(width 0.088646)
		(layer "In6.Cu")
		(net "M_C_CPU1_SA_DQS_DN<4>")
	)
	(arc
		(start 88.537796 -259.941314)
		(mid 88.255094 -259.865538)
		(end 87.972392 -259.941314)
		(width 0.088646)
		(layer "In6.Cu")
		(net "M_C_CPU1_SA_DQS_DN<4>")
	)
	(arc
		(start 90.791792 -259.941314)
		(mid 90.604594 -259.991457)
		(end 90.417396 -259.941314)
		(width 0.088646)
		(layer "In6.Cu")
		(net "M_C_CPU1_SA_DQS_DN<4>")
	)
	(arc
		(start 89.851992 -259.941314)
		(mid 89.664794 -259.991457)
		(end 89.477596 -259.941314)
		(width 0.088646)
		(layer "In6.Cu")
		(net "M_C_CPU1_SA_DQS_DN<4>")
	)
	(arc
		(start 91.731846 -259.941314)
		(mid 91.544648 -259.991457)
		(end 91.35745 -259.941314)
		(width 0.088646)
		(layer "In6.Cu")
		(net "M_C_CPU1_SA_DQS_DN<4>")
	)
	(arc
		(start 91.347036 -259.935218)
		(mid 91.068604 -259.865372)
		(end 90.791792 -259.941314)
		(width 0.088646)
		(layer "In6.Cu")
		(net "M_C_CPU1_SA_DQS_DN<4>")
	)
	(arc
		(start 85.718396 -259.941314)
		(mid 85.435694 -259.865538)
		(end 85.152992 -259.941314)
		(width 0.088646)
		(layer "In6.Cu")
		(net "M_C_CPU1_SA_DQS_DN<4>")
	)
	(arc
		(start 93.222064 -259.932678)
		(mid 92.945589 -259.865358)
		(end 92.671392 -259.941314)
		(width 0.088646)
		(layer "In6.Cu")
		(net "M_C_CPU1_SA_DQS_DN<4>")
	)
	(arc
		(start 84.778596 -259.941314)
		(mid 84.495894 -259.865538)
		(end 84.213192 -259.941314)
		(width 0.088646)
		(layer "In6.Cu")
		(net "M_C_CPU1_SA_DQS_DN<4>")
	)
	(arc
		(start 92.671392 -259.941314)
		(mid 92.484194 -259.991457)
		(end 92.296996 -259.941314)
		(width 0.088646)
		(layer "In6.Cu")
		(net "M_C_CPU1_SA_DQS_DN<4>")
	)
	(segment
		(start 24.55164 -284.277816)
		(end 25.187656 -284.703012)
		(width 0.20066)
		(layer "F.Cu")
		(net "M_C_CPU1_SA_DQS_DN<3>")
	)
	(segment
		(start 23.228046 -284.016704)
		(end 23.776686 -284.016704)
		(width 0.20066)
		(layer "F.Cu")
		(net "M_C_CPU1_SA_DQS_DN<3>")
	)
	(segment
		(start 26.204672 -284.430978)
		(end 26.21534 -284.441646)
		(width 0.101854)
		(layer "F.Cu")
		(net "M_C_CPU1_SA_DQS_DN<3>")
	)
	(segment
		(start 23.776686 -284.016704)
		(end 24.037798 -284.277816)
		(width 0.20066)
		(layer "F.Cu")
		(net "M_C_CPU1_SA_DQS_DN<3>")
	)
	(segment
		(start 94.833694 -264.778236)
		(end 94.833948 -265.314176)
		(width 0.20066)
		(layer "F.Cu")
		(net "M_C_CPU1_SA_DQS_DN<3>")
	)
	(segment
		(start 31.876746 -284.016704)
		(end 30.771846 -284.016704)
		(width 0.20066)
		(layer "F.Cu")
		(net "M_C_CPU1_SA_DQS_DN<3>")
	)
	(segment
		(start 29.132276 -284.703012)
		(end 29.557472 -284.277816)
		(width 0.20066)
		(layer "F.Cu")
		(net "M_C_CPU1_SA_DQS_DN<3>")
	)
	(segment
		(start 28.945586 -284.703012)
		(end 29.132276 -284.703012)
		(width 0.20066)
		(layer "F.Cu")
		(net "M_C_CPU1_SA_DQS_DN<3>")
	)
	(segment
		(start 26.21534 -284.441646)
		(end 28.529026 -284.441646)
		(width 0.1016)
		(layer "F.Cu")
		(net "M_C_CPU1_SA_DQS_DN<3>")
	)
	(segment
		(start 28.529026 -284.441646)
		(end 28.68422 -284.441646)
		(width 0.20066)
		(layer "F.Cu")
		(net "M_C_CPU1_SA_DQS_DN<3>")
	)
	(segment
		(start 24.037798 -284.277816)
		(end 24.55164 -284.277816)
		(width 0.20066)
		(layer "F.Cu")
		(net "M_C_CPU1_SA_DQS_DN<3>")
	)
	(segment
		(start 26.20391 -284.430978)
		(end 26.204672 -284.430978)
		(width 0.101854)
		(layer "F.Cu")
		(net "M_C_CPU1_SA_DQS_DN<3>")
	)
	(segment
		(start 28.68422 -284.441646)
		(end 28.945586 -284.703012)
		(width 0.20066)
		(layer "F.Cu")
		(net "M_C_CPU1_SA_DQS_DN<3>")
	)
	(segment
		(start 25.999694 -284.430978)
		(end 26.20391 -284.430978)
		(width 0.20066)
		(layer "F.Cu")
		(net "M_C_CPU1_SA_DQS_DN<3>")
	)
	(segment
		(start 29.557472 -284.277816)
		(end 29.964126 -284.277816)
		(width 0.20066)
		(layer "F.Cu")
		(net "M_C_CPU1_SA_DQS_DN<3>")
	)
	(segment
		(start 25.72766 -284.703012)
		(end 25.999694 -284.430978)
		(width 0.20066)
		(layer "F.Cu")
		(net "M_C_CPU1_SA_DQS_DN<3>")
	)
	(segment
		(start 25.187656 -284.703012)
		(end 25.72766 -284.703012)
		(width 0.20066)
		(layer "F.Cu")
		(net "M_C_CPU1_SA_DQS_DN<3>")
	)
	(segment
		(start 30.225238 -284.016704)
		(end 30.771846 -284.016704)
		(width 0.20066)
		(layer "F.Cu")
		(net "M_C_CPU1_SA_DQS_DN<3>")
	)
	(segment
		(start 29.964126 -284.277816)
		(end 30.225238 -284.016704)
		(width 0.20066)
		(layer "F.Cu")
		(net "M_C_CPU1_SA_DQS_DN<3>")
	)
	(segment
		(start 69.254624 -273.98345)
		(end 69.254624 -274.159472)
		(width 0.18288)
		(layer "In6.Cu")
		(net "M_C_CPU1_SA_DQS_DN<3>")
	)
	(segment
		(start 93.707204 -265.638534)
		(end 93.70695 -265.638534)
		(width 0.088646)
		(layer "In6.Cu")
		(net "M_C_CPU1_SA_DQS_DN<3>")
	)
	(segment
		(start 62.593474 -277.160228)
		(end 59.913774 -277.160228)
		(width 0.18288)
		(layer "In6.Cu")
		(net "M_C_CPU1_SA_DQS_DN<3>")
	)
	(segment
		(start 66.576702 -276.013926)
		(end 66.509392 -276.176994)
		(width 0.18288)
		(layer "In6.Cu")
		(net "M_C_CPU1_SA_DQS_DN<3>")
	)
	(segment
		(start 67.246246 -275.871178)
		(end 67.083686 -275.803868)
		(width 0.18288)
		(layer "In6.Cu")
		(net "M_C_CPU1_SA_DQS_DN<3>")
	)
	(segment
		(start 74.777346 -270.621252)
		(end 74.710036 -270.784066)
		(width 0.18288)
		(layer "In6.Cu")
		(net "M_C_CPU1_SA_DQS_DN<3>")
	)
	(segment
		(start 68.302632 -274.935442)
		(end 68.302632 -275.111464)
		(width 0.18288)
		(layer "In6.Cu")
		(net "M_C_CPU1_SA_DQS_DN<3>")
	)
	(segment
		(start 83.062572 -267.650976)
		(end 83.039204 -267.650976)
		(width 0.088646)
		(layer "In6.Cu")
		(net "M_C_CPU1_SA_DQS_DN<3>")
	)
	(segment
		(start 36.520374 -284.70733)
		(end 36.25469 -284.441646)
		(width 0.18288)
		(layer "In6.Cu")
		(net "M_C_CPU1_SA_DQS_DN<3>")
	)
	(segment
		(start 72.22236 -271.814798)
		(end 71.158608 -272.255488)
		(width 0.18288)
		(layer "In6.Cu")
		(net "M_C_CPU1_SA_DQS_DN<3>")
	)
	(segment
		(start 35.505644 -284.690058)
		(end 34.85515 -284.690058)
		(width 0.18288)
		(layer "In6.Cu")
		(net "M_C_CPU1_SA_DQS_DN<3>")
	)
	(segment
		(start 34.85515 -284.690058)
		(end 34.497518 -284.332934)
		(width 0.18288)
		(layer "In6.Cu")
		(net "M_C_CPU1_SA_DQS_DN<3>")
	)
	(segment
		(start 75.447144 -270.478504)
		(end 75.284584 -270.411194)
		(width 0.18288)
		(layer "In6.Cu")
		(net "M_C_CPU1_SA_DQS_DN<3>")
	)
	(segment
		(start 75.953874 -270.2687)
		(end 75.447144 -270.478504)
		(width 0.18288)
		(layer "In6.Cu")
		(net "M_C_CPU1_SA_DQS_DN<3>")
	)
	(segment
		(start 85.505798 -265.72845)
		(end 85.291168 -265.94308)
		(width 0.088646)
		(layer "In6.Cu")
		(net "M_C_CPU1_SA_DQS_DN<3>")
	)
	(segment
		(start 47.242476 -281.041856)
		(end 46.741334 -281.041856)
		(width 0.18288)
		(layer "In6.Cu")
		(net "M_C_CPU1_SA_DQS_DN<3>")
	)
	(segment
		(start 69.642736 -273.595338)
		(end 69.254624 -273.98345)
		(width 0.18288)
		(layer "In6.Cu")
		(net "M_C_CPU1_SA_DQS_DN<3>")
	)
	(segment
		(start 93.156278 -265.629898)
		(end 93.141546 -265.638534)
		(width 0.088646)
		(layer "In6.Cu")
		(net "M_C_CPU1_SA_DQS_DN<3>")
	)
	(segment
		(start 65.190878 -276.723602)
		(end 64.267334 -277.647146)
		(width 0.18288)
		(layer "In6.Cu")
		(net "M_C_CPU1_SA_DQS_DN<3>")
	)
	(segment
		(start 69.818758 -273.595338)
		(end 69.642736 -273.595338)
		(width 0.18288)
		(layer "In6.Cu")
		(net "M_C_CPU1_SA_DQS_DN<3>")
	)
	(segment
		(start 76.528422 -269.895828)
		(end 76.021184 -270.105886)
		(width 0.18288)
		(layer "In6.Cu")
		(net "M_C_CPU1_SA_DQS_DN<3>")
	)
	(segment
		(start 50.841402 -280.191718)
		(end 50.579782 -280.453338)
		(width 0.18288)
		(layer "In6.Cu")
		(net "M_C_CPU1_SA_DQS_DN<3>")
	)
	(segment
		(start 83.703668 -267.710666)
		(end 83.122262 -267.710666)
		(width 0.088646)
		(layer "In6.Cu")
		(net "M_C_CPU1_SA_DQS_DN<3>")
	)
	(segment
		(start 82.272632 -267.650976)
		(end 77.93482 -269.447772)
		(width 0.18288)
		(layer "In6.Cu")
		(net "M_C_CPU1_SA_DQS_DN<3>")
	)
	(segment
		(start 77.77226 -269.380462)
		(end 77.265022 -269.59052)
		(width 0.18288)
		(layer "In6.Cu")
		(net "M_C_CPU1_SA_DQS_DN<3>")
	)
	(segment
		(start 63.770002 -277.647146)
		(end 62.593474 -277.160228)
		(width 0.18288)
		(layer "In6.Cu")
		(net "M_C_CPU1_SA_DQS_DN<3>")
	)
	(segment
		(start 75.284584 -270.411194)
		(end 74.777346 -270.621252)
		(width 0.18288)
		(layer "In6.Cu")
		(net "M_C_CPU1_SA_DQS_DN<3>")
	)
	(segment
		(start 84.050378 -266.858242)
		(end 84.050378 -267.363956)
		(width 0.088646)
		(layer "In6.Cu")
		(net "M_C_CPU1_SA_DQS_DN<3>")
	)
	(segment
		(start 83.122262 -267.710666)
		(end 83.062572 -267.650976)
		(width 0.088646)
		(layer "In6.Cu")
		(net "M_C_CPU1_SA_DQS_DN<3>")
	)
	(segment
		(start 33.8709 -284.073346)
		(end 33.076642 -284.073346)
		(width 0.18288)
		(layer "In6.Cu")
		(net "M_C_CPU1_SA_DQS_DN<3>")
	)
	(segment
		(start 58.215784 -277.863808)
		(end 56.215026 -277.863808)
		(width 0.18288)
		(layer "In6.Cu")
		(net "M_C_CPU1_SA_DQS_DN<3>")
	)
	(segment
		(start 46.49216 -281.29103)
		(end 46.138338 -281.29103)
		(width 0.18288)
		(layer "In6.Cu")
		(net "M_C_CPU1_SA_DQS_DN<3>")
	)
	(segment
		(start 59.913774 -277.160228)
		(end 58.215784 -277.863808)
		(width 0.18288)
		(layer "In6.Cu")
		(net "M_C_CPU1_SA_DQS_DN<3>")
	)
	(segment
		(start 50.210212 -280.453338)
		(end 49.401984 -280.78811)
		(width 0.18288)
		(layer "In6.Cu")
		(net "M_C_CPU1_SA_DQS_DN<3>")
	)
	(segment
		(start 68.866766 -274.54733)
		(end 68.690744 -274.54733)
		(width 0.18288)
		(layer "In6.Cu")
		(net "M_C_CPU1_SA_DQS_DN<3>")
	)
	(segment
		(start 90.332306 -265.632438)
		(end 90.321892 -265.638534)
		(width 0.088646)
		(layer "In6.Cu")
		(net "M_C_CPU1_SA_DQS_DN<3>")
	)
	(segment
		(start 56.215026 -277.863808)
		(end 55.594758 -278.484076)
		(width 0.18288)
		(layer "In6.Cu")
		(net "M_C_CPU1_SA_DQS_DN<3>")
	)
	(segment
		(start 54.575456 -280.452068)
		(end 51.602894 -280.452068)
		(width 0.18288)
		(layer "In6.Cu")
		(net "M_C_CPU1_SA_DQS_DN<3>")
	)
	(segment
		(start 41.600628 -283.919422)
		(end 39.699438 -284.70733)
		(width 0.18288)
		(layer "In6.Cu")
		(net "M_C_CPU1_SA_DQS_DN<3>")
	)
	(segment
		(start 77.197712 -269.753334)
		(end 76.690982 -269.963138)
		(width 0.18288)
		(layer "In6.Cu")
		(net "M_C_CPU1_SA_DQS_DN<3>")
	)
	(segment
		(start 68.302632 -275.111464)
		(end 67.752976 -275.66112)
		(width 0.18288)
		(layer "In6.Cu")
		(net "M_C_CPU1_SA_DQS_DN<3>")
	)
	(segment
		(start 85.291168 -265.94308)
		(end 84.96554 -265.94308)
		(width 0.088646)
		(layer "In6.Cu")
		(net "M_C_CPU1_SA_DQS_DN<3>")
	)
	(segment
		(start 72.28967 -271.651984)
		(end 72.22236 -271.814798)
		(width 0.18288)
		(layer "In6.Cu")
		(net "M_C_CPU1_SA_DQS_DN<3>")
	)
	(segment
		(start 94.802198 -265.43)
		(end 94.763336 -265.452098)
		(width 0.088646)
		(layer "In6.Cu")
		(net "M_C_CPU1_SA_DQS_DN<3>")
	)
	(segment
		(start 45.66285 -281.488134)
		(end 44.962064 -282.18892)
		(width 0.18288)
		(layer "In6.Cu")
		(net "M_C_CPU1_SA_DQS_DN<3>")
	)
	(segment
		(start 34.497518 -284.332934)
		(end 33.8709 -284.073346)
		(width 0.18288)
		(layer "In6.Cu")
		(net "M_C_CPU1_SA_DQS_DN<3>")
	)
	(segment
		(start 33.076642 -284.073346)
		(end 32.588454 -284.27553)
		(width 0.18288)
		(layer "In6.Cu")
		(net "M_C_CPU1_SA_DQS_DN<3>")
	)
	(segment
		(start 94.60865 -265.492992)
		(end 94.335092 -265.492992)
		(width 0.088646)
		(layer "In6.Cu")
		(net "M_C_CPU1_SA_DQS_DN<3>")
	)
	(segment
		(start 67.083686 -275.803868)
		(end 66.576702 -276.013926)
		(width 0.18288)
		(layer "In6.Cu")
		(net "M_C_CPU1_SA_DQS_DN<3>")
	)
	(segment
		(start 70.594728 -272.643346)
		(end 70.206616 -273.031458)
		(width 0.18288)
		(layer "In6.Cu")
		(net "M_C_CPU1_SA_DQS_DN<3>")
	)
	(segment
		(start 51.342544 -280.191718)
		(end 50.841402 -280.191718)
		(width 0.18288)
		(layer "In6.Cu")
		(net "M_C_CPU1_SA_DQS_DN<3>")
	)
	(segment
		(start 77.93482 -269.447772)
		(end 77.77226 -269.380462)
		(width 0.18288)
		(layer "In6.Cu")
		(net "M_C_CPU1_SA_DQS_DN<3>")
	)
	(segment
		(start 74.710036 -270.784066)
		(end 74.203306 -270.99387)
		(width 0.18288)
		(layer "In6.Cu")
		(net "M_C_CPU1_SA_DQS_DN<3>")
	)
	(segment
		(start 71.158608 -272.255488)
		(end 70.77075 -272.643346)
		(width 0.18288)
		(layer "In6.Cu")
		(net "M_C_CPU1_SA_DQS_DN<3>")
	)
	(segment
		(start 72.959468 -271.509236)
		(end 72.796908 -271.441926)
		(width 0.18288)
		(layer "In6.Cu")
		(net "M_C_CPU1_SA_DQS_DN<3>")
	)
	(segment
		(start 54.924706 -280.102564)
		(end 54.575456 -280.452068)
		(width 0.18288)
		(layer "In6.Cu")
		(net "M_C_CPU1_SA_DQS_DN<3>")
	)
	(segment
		(start 68.690744 -274.54733)
		(end 68.302632 -274.935442)
		(width 0.18288)
		(layer "In6.Cu")
		(net "M_C_CPU1_SA_DQS_DN<3>")
	)
	(segment
		(start 84.050378 -267.363956)
		(end 83.703668 -267.710666)
		(width 0.088646)
		(layer "In6.Cu")
		(net "M_C_CPU1_SA_DQS_DN<3>")
	)
	(segment
		(start 49.10201 -281.088084)
		(end 48.58512 -281.302206)
		(width 0.18288)
		(layer "In6.Cu")
		(net "M_C_CPU1_SA_DQS_DN<3>")
	)
	(segment
		(start 36.25469 -284.441646)
		(end 35.754056 -284.441646)
		(width 0.18288)
		(layer "In6.Cu")
		(net "M_C_CPU1_SA_DQS_DN<3>")
	)
	(segment
		(start 83.039204 -267.650976)
		(end 82.272632 -267.650976)
		(width 0.18288)
		(layer "In6.Cu")
		(net "M_C_CPU1_SA_DQS_DN<3>")
	)
	(segment
		(start 67.752976 -275.66112)
		(end 67.246246 -275.871178)
		(width 0.18288)
		(layer "In6.Cu")
		(net "M_C_CPU1_SA_DQS_DN<3>")
	)
	(segment
		(start 73.466198 -271.299432)
		(end 72.959468 -271.509236)
		(width 0.18288)
		(layer "In6.Cu")
		(net "M_C_CPU1_SA_DQS_DN<3>")
	)
	(segment
		(start 47.502826 -281.302206)
		(end 47.242476 -281.041856)
		(width 0.18288)
		(layer "In6.Cu")
		(net "M_C_CPU1_SA_DQS_DN<3>")
	)
	(segment
		(start 46.741334 -281.041856)
		(end 46.49216 -281.29103)
		(width 0.18288)
		(layer "In6.Cu")
		(net "M_C_CPU1_SA_DQS_DN<3>")
	)
	(segment
		(start 48.58512 -281.302206)
		(end 47.502826 -281.302206)
		(width 0.18288)
		(layer "In6.Cu")
		(net "M_C_CPU1_SA_DQS_DN<3>")
	)
	(segment
		(start 77.265022 -269.59052)
		(end 77.197712 -269.753334)
		(width 0.18288)
		(layer "In6.Cu")
		(net "M_C_CPU1_SA_DQS_DN<3>")
	)
	(segment
		(start 42.178478 -283.341572)
		(end 41.600628 -283.919422)
		(width 0.18288)
		(layer "In6.Cu")
		(net "M_C_CPU1_SA_DQS_DN<3>")
	)
	(segment
		(start 69.254624 -274.159472)
		(end 68.866766 -274.54733)
		(width 0.18288)
		(layer "In6.Cu")
		(net "M_C_CPU1_SA_DQS_DN<3>")
	)
	(segment
		(start 49.401984 -280.78811)
		(end 49.10201 -281.088084)
		(width 0.18288)
		(layer "In6.Cu")
		(net "M_C_CPU1_SA_DQS_DN<3>")
	)
	(segment
		(start 64.267334 -277.647146)
		(end 63.770002 -277.647146)
		(width 0.18288)
		(layer "In6.Cu")
		(net "M_C_CPU1_SA_DQS_DN<3>")
	)
	(segment
		(start 76.690982 -269.963138)
		(end 76.528422 -269.895828)
		(width 0.18288)
		(layer "In6.Cu")
		(net "M_C_CPU1_SA_DQS_DN<3>")
	)
	(segment
		(start 74.203306 -270.99387)
		(end 74.040746 -270.92656)
		(width 0.18288)
		(layer "In6.Cu")
		(net "M_C_CPU1_SA_DQS_DN<3>")
	)
	(segment
		(start 55.594758 -278.484076)
		(end 54.924706 -280.102564)
		(width 0.18288)
		(layer "In6.Cu")
		(net "M_C_CPU1_SA_DQS_DN<3>")
	)
	(segment
		(start 74.040746 -270.92656)
		(end 73.533508 -271.136618)
		(width 0.18288)
		(layer "In6.Cu")
		(net "M_C_CPU1_SA_DQS_DN<3>")
	)
	(segment
		(start 70.77075 -272.643346)
		(end 70.594728 -272.643346)
		(width 0.18288)
		(layer "In6.Cu")
		(net "M_C_CPU1_SA_DQS_DN<3>")
	)
	(segment
		(start 92.211906 -265.632438)
		(end 92.201492 -265.638534)
		(width 0.088646)
		(layer "In6.Cu")
		(net "M_C_CPU1_SA_DQS_DN<3>")
	)
	(segment
		(start 94.081854 -265.638788)
		(end 94.0816 -265.638534)
		(width 0.088646)
		(layer "In6.Cu")
		(net "M_C_CPU1_SA_DQS_DN<3>")
	)
	(segment
		(start 94.833948 -265.314176)
		(end 94.802198 -265.43)
		(width 0.088646)
		(layer "In6.Cu")
		(net "M_C_CPU1_SA_DQS_DN<3>")
	)
	(segment
		(start 70.206616 -273.20748)
		(end 69.818758 -273.595338)
		(width 0.18288)
		(layer "In6.Cu")
		(net "M_C_CPU1_SA_DQS_DN<3>")
	)
	(segment
		(start 66.509392 -276.176994)
		(end 65.190878 -276.723602)
		(width 0.18288)
		(layer "In6.Cu")
		(net "M_C_CPU1_SA_DQS_DN<3>")
	)
	(segment
		(start 84.96554 -265.94308)
		(end 84.050378 -266.858242)
		(width 0.088646)
		(layer "In6.Cu")
		(net "M_C_CPU1_SA_DQS_DN<3>")
	)
	(segment
		(start 32.588454 -284.27553)
		(end 32.135572 -284.27553)
		(width 0.18288)
		(layer "In6.Cu")
		(net "M_C_CPU1_SA_DQS_DN<3>")
	)
	(segment
		(start 51.602894 -280.452068)
		(end 51.342544 -280.191718)
		(width 0.18288)
		(layer "In6.Cu")
		(net "M_C_CPU1_SA_DQS_DN<3>")
	)
	(segment
		(start 44.962064 -282.18892)
		(end 42.178478 -283.341572)
		(width 0.18288)
		(layer "In6.Cu")
		(net "M_C_CPU1_SA_DQS_DN<3>")
	)
	(segment
		(start 35.754056 -284.441646)
		(end 35.505644 -284.690058)
		(width 0.18288)
		(layer "In6.Cu")
		(net "M_C_CPU1_SA_DQS_DN<3>")
	)
	(segment
		(start 39.699438 -284.70733)
		(end 36.520374 -284.70733)
		(width 0.18288)
		(layer "In6.Cu")
		(net "M_C_CPU1_SA_DQS_DN<3>")
	)
	(segment
		(start 72.796908 -271.441926)
		(end 72.28967 -271.651984)
		(width 0.18288)
		(layer "In6.Cu")
		(net "M_C_CPU1_SA_DQS_DN<3>")
	)
	(segment
		(start 91.27236 -265.632438)
		(end 91.261946 -265.638534)
		(width 0.088646)
		(layer "In6.Cu")
		(net "M_C_CPU1_SA_DQS_DN<3>")
	)
	(segment
		(start 73.533508 -271.136618)
		(end 73.466198 -271.299432)
		(width 0.18288)
		(layer "In6.Cu")
		(net "M_C_CPU1_SA_DQS_DN<3>")
	)
	(segment
		(start 76.021184 -270.105886)
		(end 75.953874 -270.2687)
		(width 0.18288)
		(layer "In6.Cu")
		(net "M_C_CPU1_SA_DQS_DN<3>")
	)
	(segment
		(start 70.206616 -273.031458)
		(end 70.206616 -273.20748)
		(width 0.18288)
		(layer "In6.Cu")
		(net "M_C_CPU1_SA_DQS_DN<3>")
	)
	(segment
		(start 50.579782 -280.453338)
		(end 50.210212 -280.453338)
		(width 0.18288)
		(layer "In6.Cu")
		(net "M_C_CPU1_SA_DQS_DN<3>")
	)
	(segment
		(start 46.138338 -281.29103)
		(end 45.66285 -281.488134)
		(width 0.18288)
		(layer "In6.Cu")
		(net "M_C_CPU1_SA_DQS_DN<3>")
	)
	(segment
		(start 94.335092 -265.492992)
		(end 94.081854 -265.638788)
		(width 0.088646)
		(layer "In6.Cu")
		(net "M_C_CPU1_SA_DQS_DN<3>")
	)
	(segment
		(start 32.135572 -284.27553)
		(end 31.876746 -284.016704)
		(width 0.18288)
		(layer "In6.Cu")
		(net "M_C_CPU1_SA_DQS_DN<3>")
	)
	(arc
		(start 89.007696 -265.638534)
		(mid 88.724994 -265.562758)
		(end 88.442292 -265.638534)
		(width 0.088646)
		(layer "In6.Cu")
		(net "M_C_CPU1_SA_DQS_DN<3>")
	)
	(arc
		(start 93.70695 -265.638534)
		(mid 93.432721 -265.562609)
		(end 93.156278 -265.629898)
		(width 0.088646)
		(layer "In6.Cu")
		(net "M_C_CPU1_SA_DQS_DN<3>")
	)
	(arc
		(start 90.321892 -265.638534)
		(mid 90.134694 -265.688677)
		(end 89.947496 -265.638534)
		(width 0.088646)
		(layer "In6.Cu")
		(net "M_C_CPU1_SA_DQS_DN<3>")
	)
	(arc
		(start 94.0816 -265.638534)
		(mid 93.894402 -265.688677)
		(end 93.707204 -265.638534)
		(width 0.088646)
		(layer "In6.Cu")
		(net "M_C_CPU1_SA_DQS_DN<3>")
	)
	(arc
		(start 87.128096 -265.638534)
		(mid 86.845394 -265.562792)
		(end 86.562692 -265.638534)
		(width 0.088646)
		(layer "In6.Cu")
		(net "M_C_CPU1_SA_DQS_DN<3>")
	)
	(arc
		(start 88.442292 -265.638534)
		(mid 88.255094 -265.688677)
		(end 88.067896 -265.638534)
		(width 0.088646)
		(layer "In6.Cu")
		(net "M_C_CPU1_SA_DQS_DN<3>")
	)
	(arc
		(start 86.188296 -265.638534)
		(mid 85.831773 -265.567631)
		(end 85.505798 -265.72845)
		(width 0.088646)
		(layer "In6.Cu")
		(net "M_C_CPU1_SA_DQS_DN<3>")
	)
	(arc
		(start 93.141546 -265.638534)
		(mid 92.954348 -265.688677)
		(end 92.76715 -265.638534)
		(width 0.088646)
		(layer "In6.Cu")
		(net "M_C_CPU1_SA_DQS_DN<3>")
	)
	(arc
		(start 92.201492 -265.638534)
		(mid 92.014294 -265.688677)
		(end 91.827096 -265.638534)
		(width 0.088646)
		(layer "In6.Cu")
		(net "M_C_CPU1_SA_DQS_DN<3>")
	)
	(arc
		(start 88.067896 -265.638534)
		(mid 87.785194 -265.562792)
		(end 87.502492 -265.638534)
		(width 0.088646)
		(layer "In6.Cu")
		(net "M_C_CPU1_SA_DQS_DN<3>")
	)
	(arc
		(start 91.827096 -265.638534)
		(mid 91.550537 -265.562791)
		(end 91.27236 -265.632438)
		(width 0.088646)
		(layer "In6.Cu")
		(net "M_C_CPU1_SA_DQS_DN<3>")
	)
	(arc
		(start 87.502492 -265.638534)
		(mid 87.315294 -265.688677)
		(end 87.128096 -265.638534)
		(width 0.088646)
		(layer "In6.Cu")
		(net "M_C_CPU1_SA_DQS_DN<3>")
	)
	(arc
		(start 89.382092 -265.638534)
		(mid 89.194894 -265.688677)
		(end 89.007696 -265.638534)
		(width 0.088646)
		(layer "In6.Cu")
		(net "M_C_CPU1_SA_DQS_DN<3>")
	)
	(arc
		(start 90.88755 -265.638534)
		(mid 90.610737 -265.562664)
		(end 90.332306 -265.632438)
		(width 0.088646)
		(layer "In6.Cu")
		(net "M_C_CPU1_SA_DQS_DN<3>")
	)
	(arc
		(start 91.261946 -265.638534)
		(mid 91.074748 -265.688677)
		(end 90.88755 -265.638534)
		(width 0.088646)
		(layer "In6.Cu")
		(net "M_C_CPU1_SA_DQS_DN<3>")
	)
	(arc
		(start 86.562692 -265.638534)
		(mid 86.375494 -265.688677)
		(end 86.188296 -265.638534)
		(width 0.088646)
		(layer "In6.Cu")
		(net "M_C_CPU1_SA_DQS_DN<3>")
	)
	(arc
		(start 94.763336 -265.452098)
		(mid 94.688651 -265.482603)
		(end 94.60865 -265.492992)
		(width 0.088646)
		(layer "In6.Cu")
		(net "M_C_CPU1_SA_DQS_DN<3>")
	)
	(arc
		(start 89.947496 -265.638534)
		(mid 89.664794 -265.562758)
		(end 89.382092 -265.638534)
		(width 0.088646)
		(layer "In6.Cu")
		(net "M_C_CPU1_SA_DQS_DN<3>")
	)
	(arc
		(start 92.76715 -265.638534)
		(mid 92.490337 -265.562664)
		(end 92.211906 -265.632438)
		(width 0.088646)
		(layer "In6.Cu")
		(net "M_C_CPU1_SA_DQS_DN<3>")
	)
	(segment
		(start 26.20391 -293.780972)
		(end 26.204672 -293.780972)
		(width 0.101854)
		(layer "F.Cu")
		(net "M_C_CPU1_SA_DQS_DN<2>")
	)
	(segment
		(start 29.964126 -293.62781)
		(end 30.225238 -293.366698)
		(width 0.20066)
		(layer "F.Cu")
		(net "M_C_CPU1_SA_DQS_DN<2>")
	)
	(segment
		(start 25.72766 -294.053006)
		(end 25.999694 -293.780972)
		(width 0.20066)
		(layer "F.Cu")
		(net "M_C_CPU1_SA_DQS_DN<2>")
	)
	(segment
		(start 29.132276 -294.053006)
		(end 29.557472 -293.62781)
		(width 0.20066)
		(layer "F.Cu")
		(net "M_C_CPU1_SA_DQS_DN<2>")
	)
	(segment
		(start 31.876746 -293.366698)
		(end 30.771846 -293.366698)
		(width 0.20066)
		(layer "F.Cu")
		(net "M_C_CPU1_SA_DQS_DN<2>")
	)
	(segment
		(start 28.945586 -294.053006)
		(end 29.132276 -294.053006)
		(width 0.20066)
		(layer "F.Cu")
		(net "M_C_CPU1_SA_DQS_DN<2>")
	)
	(segment
		(start 26.21534 -293.79164)
		(end 28.529026 -293.79164)
		(width 0.1016)
		(layer "F.Cu")
		(net "M_C_CPU1_SA_DQS_DN<2>")
	)
	(segment
		(start 29.557472 -293.62781)
		(end 29.964126 -293.62781)
		(width 0.20066)
		(layer "F.Cu")
		(net "M_C_CPU1_SA_DQS_DN<2>")
	)
	(segment
		(start 23.776686 -293.366698)
		(end 24.037798 -293.62781)
		(width 0.20066)
		(layer "F.Cu")
		(net "M_C_CPU1_SA_DQS_DN<2>")
	)
	(segment
		(start 26.204672 -293.780972)
		(end 26.21534 -293.79164)
		(width 0.101854)
		(layer "F.Cu")
		(net "M_C_CPU1_SA_DQS_DN<2>")
	)
	(segment
		(start 25.187656 -294.053006)
		(end 25.72766 -294.053006)
		(width 0.20066)
		(layer "F.Cu")
		(net "M_C_CPU1_SA_DQS_DN<2>")
	)
	(segment
		(start 91.544648 -267.219938)
		(end 91.544394 -267.755878)
		(width 0.20066)
		(layer "F.Cu")
		(net "M_C_CPU1_SA_DQS_DN<2>")
	)
	(segment
		(start 28.529026 -293.79164)
		(end 28.68422 -293.79164)
		(width 0.20066)
		(layer "F.Cu")
		(net "M_C_CPU1_SA_DQS_DN<2>")
	)
	(segment
		(start 30.225238 -293.366698)
		(end 30.771846 -293.366698)
		(width 0.20066)
		(layer "F.Cu")
		(net "M_C_CPU1_SA_DQS_DN<2>")
	)
	(segment
		(start 24.037798 -293.62781)
		(end 24.55164 -293.62781)
		(width 0.20066)
		(layer "F.Cu")
		(net "M_C_CPU1_SA_DQS_DN<2>")
	)
	(segment
		(start 24.55164 -293.62781)
		(end 25.187656 -294.053006)
		(width 0.20066)
		(layer "F.Cu")
		(net "M_C_CPU1_SA_DQS_DN<2>")
	)
	(segment
		(start 23.228046 -293.366698)
		(end 23.776686 -293.366698)
		(width 0.20066)
		(layer "F.Cu")
		(net "M_C_CPU1_SA_DQS_DN<2>")
	)
	(segment
		(start 28.68422 -293.79164)
		(end 28.945586 -294.053006)
		(width 0.20066)
		(layer "F.Cu")
		(net "M_C_CPU1_SA_DQS_DN<2>")
	)
	(segment
		(start 25.999694 -293.780972)
		(end 26.20391 -293.780972)
		(width 0.20066)
		(layer "F.Cu")
		(net "M_C_CPU1_SA_DQS_DN<2>")
	)
	(segment
		(start 81.106518 -270.59001)
		(end 80.930496 -270.59001)
		(width 0.18288)
		(layer "In4.Cu")
		(net "M_C_CPU1_SA_DQS_DN<2>")
	)
	(segment
		(start 50.177446 -294.060372)
		(end 48.772826 -294.643302)
		(width 0.18288)
		(layer "In4.Cu")
		(net "M_C_CPU1_SA_DQS_DN<2>")
	)
	(segment
		(start 69.640958 -284.550358)
		(end 66.362834 -287.828228)
		(width 0.18288)
		(layer "In4.Cu")
		(net "M_C_CPU1_SA_DQS_DN<2>")
	)
	(segment
		(start 74.830432 -276.866096)
		(end 71.405496 -280.290778)
		(width 0.18288)
		(layer "In4.Cu")
		(net "M_C_CPU1_SA_DQS_DN<2>")
	)
	(segment
		(start 78.07452 -273.445986)
		(end 77.686408 -273.834098)
		(width 0.18288)
		(layer "In4.Cu")
		(net "M_C_CPU1_SA_DQS_DN<2>")
	)
	(segment
		(start 53.328062 -292.965378)
		(end 52.216812 -294.076628)
		(width 0.18288)
		(layer "In4.Cu")
		(net "M_C_CPU1_SA_DQS_DN<2>")
	)
	(segment
		(start 41.067228 -293.386764)
		(end 39.435532 -294.063166)
		(width 0.18288)
		(layer "In4.Cu")
		(net "M_C_CPU1_SA_DQS_DN<2>")
	)
	(segment
		(start 35.785044 -293.79164)
		(end 35.507676 -294.069008)
		(width 0.18288)
		(layer "In4.Cu")
		(net "M_C_CPU1_SA_DQS_DN<2>")
	)
	(segment
		(start 75.782424 -275.738082)
		(end 75.782424 -275.914104)
		(width 0.18288)
		(layer "In4.Cu")
		(net "M_C_CPU1_SA_DQS_DN<2>")
	)
	(segment
		(start 47.173642 -294.641778)
		(end 46.768512 -294.641778)
		(width 0.18288)
		(layer "In4.Cu")
		(net "M_C_CPU1_SA_DQS_DN<2>")
	)
	(segment
		(start 89.855802 -268.078204)
		(end 89.852246 -268.080236)
		(width 0.088646)
		(layer "In4.Cu")
		(net "M_C_CPU1_SA_DQS_DN<2>")
	)
	(segment
		(start 76.170536 -275.34997)
		(end 75.782424 -275.738082)
		(width 0.18288)
		(layer "In4.Cu")
		(net "M_C_CPU1_SA_DQS_DN<2>")
	)
	(segment
		(start 59.412378 -291.890958)
		(end 56.8198 -292.965378)
		(width 0.18288)
		(layer "In4.Cu")
		(net "M_C_CPU1_SA_DQS_DN<2>")
	)
	(segment
		(start 35.009836 -294.069008)
		(end 34.319718 -293.37889)
		(width 0.18288)
		(layer "In4.Cu")
		(net "M_C_CPU1_SA_DQS_DN<2>")
	)
	(segment
		(start 51.277774 -293.791894)
		(end 50.869596 -293.791894)
		(width 0.18288)
		(layer "In4.Cu")
		(net "M_C_CPU1_SA_DQS_DN<2>")
	)
	(segment
		(start 79.590392 -271.930114)
		(end 79.590392 -272.106136)
		(width 0.18288)
		(layer "In4.Cu")
		(net "M_C_CPU1_SA_DQS_DN<2>")
	)
	(segment
		(start 90.41765 -268.080236)
		(end 90.417396 -268.080236)
		(width 0.088646)
		(layer "In4.Cu")
		(net "M_C_CPU1_SA_DQS_DN<2>")
	)
	(segment
		(start 66.362834 -287.828228)
		(end 65.96761 -287.828228)
		(width 0.18288)
		(layer "In4.Cu")
		(net "M_C_CPU1_SA_DQS_DN<2>")
	)
	(segment
		(start 80.930496 -270.59001)
		(end 80.542384 -270.978122)
		(width 0.18288)
		(layer "In4.Cu")
		(net "M_C_CPU1_SA_DQS_DN<2>")
	)
	(segment
		(start 77.686408 -274.01012)
		(end 77.29855 -274.397978)
		(width 0.18288)
		(layer "In4.Cu")
		(net "M_C_CPU1_SA_DQS_DN<2>")
	)
	(segment
		(start 85.036152 -268.169644)
		(end 84.805266 -268.400276)
		(width 0.088646)
		(layer "In4.Cu")
		(net "M_C_CPU1_SA_DQS_DN<2>")
	)
	(segment
		(start 36.514024 -294.063166)
		(end 36.242498 -293.79164)
		(width 0.18288)
		(layer "In4.Cu")
		(net "M_C_CPU1_SA_DQS_DN<2>")
	)
	(segment
		(start 65.712086 -288.482786)
		(end 65.571878 -288.62274)
		(width 0.18288)
		(layer "In4.Cu")
		(net "M_C_CPU1_SA_DQS_DN<2>")
	)
	(segment
		(start 81.494376 -270.02613)
		(end 81.494376 -270.202152)
		(width 0.18288)
		(layer "In4.Cu")
		(net "M_C_CPU1_SA_DQS_DN<2>")
	)
	(segment
		(start 65.712086 -288.083752)
		(end 65.712086 -288.482786)
		(width 0.18288)
		(layer "In4.Cu")
		(net "M_C_CPU1_SA_DQS_DN<2>")
	)
	(segment
		(start 51.562508 -294.076628)
		(end 51.277774 -293.791894)
		(width 0.18288)
		(layer "In4.Cu")
		(net "M_C_CPU1_SA_DQS_DN<2>")
	)
	(segment
		(start 88.53805 -268.08049)
		(end 88.537796 -268.080236)
		(width 0.088646)
		(layer "In4.Cu")
		(net "M_C_CPU1_SA_DQS_DN<2>")
	)
	(segment
		(start 77.29855 -274.397978)
		(end 77.122528 -274.397978)
		(width 0.18288)
		(layer "In4.Cu")
		(net "M_C_CPU1_SA_DQS_DN<2>")
	)
	(segment
		(start 71.405496 -280.290778)
		(end 69.640958 -284.550358)
		(width 0.18288)
		(layer "In4.Cu")
		(net "M_C_CPU1_SA_DQS_DN<2>")
	)
	(segment
		(start 91.319096 -267.934694)
		(end 91.045538 -267.934694)
		(width 0.088646)
		(layer "In4.Cu")
		(net "M_C_CPU1_SA_DQS_DN<2>")
	)
	(segment
		(start 50.869596 -293.791894)
		(end 50.601118 -294.060372)
		(width 0.18288)
		(layer "In4.Cu")
		(net "M_C_CPU1_SA_DQS_DN<2>")
	)
	(segment
		(start 50.601118 -294.060372)
		(end 50.177446 -294.060372)
		(width 0.18288)
		(layer "In4.Cu")
		(net "M_C_CPU1_SA_DQS_DN<2>")
	)
	(segment
		(start 83.341972 -269.31366)
		(end 83.318604 -269.31366)
		(width 0.088646)
		(layer "In4.Cu")
		(net "M_C_CPU1_SA_DQS_DN<2>")
	)
	(segment
		(start 77.122528 -274.397978)
		(end 76.734416 -274.78609)
		(width 0.18288)
		(layer "In4.Cu")
		(net "M_C_CPU1_SA_DQS_DN<2>")
	)
	(segment
		(start 36.242498 -293.79164)
		(end 35.785044 -293.79164)
		(width 0.18288)
		(layer "In4.Cu")
		(net "M_C_CPU1_SA_DQS_DN<2>")
	)
	(segment
		(start 91.045538 -267.934694)
		(end 90.7923 -268.08049)
		(width 0.088646)
		(layer "In4.Cu")
		(net "M_C_CPU1_SA_DQS_DN<2>")
	)
	(segment
		(start 44.478702 -293.386764)
		(end 41.067228 -293.386764)
		(width 0.18288)
		(layer "In4.Cu")
		(net "M_C_CPU1_SA_DQS_DN<2>")
	)
	(segment
		(start 79.590392 -272.106136)
		(end 79.202534 -272.493994)
		(width 0.18288)
		(layer "In4.Cu")
		(net "M_C_CPU1_SA_DQS_DN<2>")
	)
	(segment
		(start 75.218544 -276.301962)
		(end 74.830432 -276.690074)
		(width 0.18288)
		(layer "In4.Cu")
		(net "M_C_CPU1_SA_DQS_DN<2>")
	)
	(segment
		(start 32.794194 -293.6367)
		(end 32.146748 -293.6367)
		(width 0.18288)
		(layer "In4.Cu")
		(net "M_C_CPU1_SA_DQS_DN<2>")
	)
	(segment
		(start 34.319718 -293.37889)
		(end 33.052004 -293.37889)
		(width 0.18288)
		(layer "In4.Cu")
		(net "M_C_CPU1_SA_DQS_DN<2>")
	)
	(segment
		(start 78.6384 -273.058128)
		(end 78.250542 -273.445986)
		(width 0.18288)
		(layer "In4.Cu")
		(net "M_C_CPU1_SA_DQS_DN<2>")
	)
	(segment
		(start 35.507676 -294.069008)
		(end 35.009836 -294.069008)
		(width 0.18288)
		(layer "In4.Cu")
		(net "M_C_CPU1_SA_DQS_DN<2>")
	)
	(segment
		(start 80.542384 -271.154144)
		(end 80.154526 -271.542002)
		(width 0.18288)
		(layer "In4.Cu")
		(net "M_C_CPU1_SA_DQS_DN<2>")
	)
	(segment
		(start 63.981838 -289.017202)
		(end 61.087254 -290.21659)
		(width 0.18288)
		(layer "In4.Cu")
		(net "M_C_CPU1_SA_DQS_DN<2>")
	)
	(segment
		(start 91.544394 -267.755878)
		(end 91.512644 -267.871702)
		(width 0.088646)
		(layer "In4.Cu")
		(net "M_C_CPU1_SA_DQS_DN<2>")
	)
	(segment
		(start 39.435532 -294.063166)
		(end 36.514024 -294.063166)
		(width 0.18288)
		(layer "In4.Cu")
		(net "M_C_CPU1_SA_DQS_DN<2>")
	)
	(segment
		(start 80.154526 -271.542002)
		(end 79.978504 -271.542002)
		(width 0.18288)
		(layer "In4.Cu")
		(net "M_C_CPU1_SA_DQS_DN<2>")
	)
	(segment
		(start 48.058324 -294.643302)
		(end 47.786036 -294.91559)
		(width 0.18288)
		(layer "In4.Cu")
		(net "M_C_CPU1_SA_DQS_DN<2>")
	)
	(segment
		(start 47.447454 -294.91559)
		(end 47.173642 -294.641778)
		(width 0.18288)
		(layer "In4.Cu")
		(net "M_C_CPU1_SA_DQS_DN<2>")
	)
	(segment
		(start 78.6384 -272.882106)
		(end 78.6384 -273.058128)
		(width 0.18288)
		(layer "In4.Cu")
		(net "M_C_CPU1_SA_DQS_DN<2>")
	)
	(segment
		(start 47.786036 -294.91559)
		(end 47.447454 -294.91559)
		(width 0.18288)
		(layer "In4.Cu")
		(net "M_C_CPU1_SA_DQS_DN<2>")
	)
	(segment
		(start 83.318604 -269.31366)
		(end 82.382868 -269.31366)
		(width 0.18288)
		(layer "In4.Cu")
		(net "M_C_CPU1_SA_DQS_DN<2>")
	)
	(segment
		(start 83.619848 -269.37335)
		(end 83.401662 -269.37335)
		(width 0.088646)
		(layer "In4.Cu")
		(net "M_C_CPU1_SA_DQS_DN<2>")
	)
	(segment
		(start 82.05851 -269.638018)
		(end 81.882488 -269.638018)
		(width 0.18288)
		(layer "In4.Cu")
		(net "M_C_CPU1_SA_DQS_DN<2>")
	)
	(segment
		(start 88.917018 -268.077696)
		(end 88.906604 -268.083538)
		(width 0.088646)
		(layer "In4.Cu")
		(net "M_C_CPU1_SA_DQS_DN<2>")
	)
	(segment
		(start 84.805266 -268.400276)
		(end 84.441792 -268.551152)
		(width 0.088646)
		(layer "In4.Cu")
		(net "M_C_CPU1_SA_DQS_DN<2>")
	)
	(segment
		(start 52.216812 -294.076628)
		(end 51.562508 -294.076628)
		(width 0.18288)
		(layer "In4.Cu")
		(net "M_C_CPU1_SA_DQS_DN<2>")
	)
	(segment
		(start 76.734416 -274.78609)
		(end 76.734416 -274.962112)
		(width 0.18288)
		(layer "In4.Cu")
		(net "M_C_CPU1_SA_DQS_DN<2>")
	)
	(segment
		(start 75.394566 -276.301962)
		(end 75.218544 -276.301962)
		(width 0.18288)
		(layer "In4.Cu")
		(net "M_C_CPU1_SA_DQS_DN<2>")
	)
	(segment
		(start 81.882488 -269.638018)
		(end 81.494376 -270.02613)
		(width 0.18288)
		(layer "In4.Cu")
		(net "M_C_CPU1_SA_DQS_DN<2>")
	)
	(segment
		(start 84.441792 -268.551152)
		(end 83.619848 -269.37335)
		(width 0.088646)
		(layer "In4.Cu")
		(net "M_C_CPU1_SA_DQS_DN<2>")
	)
	(segment
		(start 56.8198 -292.965378)
		(end 53.328062 -292.965378)
		(width 0.18288)
		(layer "In4.Cu")
		(net "M_C_CPU1_SA_DQS_DN<2>")
	)
	(segment
		(start 46.768512 -294.641778)
		(end 46.503844 -294.906446)
		(width 0.18288)
		(layer "In4.Cu")
		(net "M_C_CPU1_SA_DQS_DN<2>")
	)
	(segment
		(start 79.026512 -272.493994)
		(end 78.6384 -272.882106)
		(width 0.18288)
		(layer "In4.Cu")
		(net "M_C_CPU1_SA_DQS_DN<2>")
	)
	(segment
		(start 46.503844 -294.906446)
		(end 45.998384 -294.906446)
		(width 0.18288)
		(layer "In4.Cu")
		(net "M_C_CPU1_SA_DQS_DN<2>")
	)
	(segment
		(start 79.978504 -271.542002)
		(end 79.590392 -271.930114)
		(width 0.18288)
		(layer "In4.Cu")
		(net "M_C_CPU1_SA_DQS_DN<2>")
	)
	(segment
		(start 65.571878 -288.62274)
		(end 65.20942 -288.772854)
		(width 0.18288)
		(layer "In4.Cu")
		(net "M_C_CPU1_SA_DQS_DN<2>")
	)
	(segment
		(start 65.20942 -288.772854)
		(end 63.981838 -289.017202)
		(width 0.18288)
		(layer "In4.Cu")
		(net "M_C_CPU1_SA_DQS_DN<2>")
	)
	(segment
		(start 45.998384 -294.906446)
		(end 44.478702 -293.386764)
		(width 0.18288)
		(layer "In4.Cu")
		(net "M_C_CPU1_SA_DQS_DN<2>")
	)
	(segment
		(start 80.542384 -270.978122)
		(end 80.542384 -271.154144)
		(width 0.18288)
		(layer "In4.Cu")
		(net "M_C_CPU1_SA_DQS_DN<2>")
	)
	(segment
		(start 61.087254 -290.21659)
		(end 59.412378 -291.890958)
		(width 0.18288)
		(layer "In4.Cu")
		(net "M_C_CPU1_SA_DQS_DN<2>")
	)
	(segment
		(start 76.734416 -274.962112)
		(end 76.346558 -275.34997)
		(width 0.18288)
		(layer "In4.Cu")
		(net "M_C_CPU1_SA_DQS_DN<2>")
	)
	(segment
		(start 75.782424 -275.914104)
		(end 75.394566 -276.301962)
		(width 0.18288)
		(layer "In4.Cu")
		(net "M_C_CPU1_SA_DQS_DN<2>")
	)
	(segment
		(start 81.494376 -270.202152)
		(end 81.106518 -270.59001)
		(width 0.18288)
		(layer "In4.Cu")
		(net "M_C_CPU1_SA_DQS_DN<2>")
	)
	(segment
		(start 90.7923 -268.08049)
		(end 90.792046 -268.080236)
		(width 0.088646)
		(layer "In4.Cu")
		(net "M_C_CPU1_SA_DQS_DN<2>")
	)
	(segment
		(start 65.96761 -287.828228)
		(end 65.712086 -288.083752)
		(width 0.18288)
		(layer "In4.Cu")
		(net "M_C_CPU1_SA_DQS_DN<2>")
	)
	(segment
		(start 79.202534 -272.493994)
		(end 79.026512 -272.493994)
		(width 0.18288)
		(layer "In4.Cu")
		(net "M_C_CPU1_SA_DQS_DN<2>")
	)
	(segment
		(start 74.830432 -276.690074)
		(end 74.830432 -276.866096)
		(width 0.18288)
		(layer "In4.Cu")
		(net "M_C_CPU1_SA_DQS_DN<2>")
	)
	(segment
		(start 77.686408 -273.834098)
		(end 77.686408 -274.01012)
		(width 0.18288)
		(layer "In4.Cu")
		(net "M_C_CPU1_SA_DQS_DN<2>")
	)
	(segment
		(start 33.052004 -293.37889)
		(end 32.794194 -293.6367)
		(width 0.18288)
		(layer "In4.Cu")
		(net "M_C_CPU1_SA_DQS_DN<2>")
	)
	(segment
		(start 32.146748 -293.6367)
		(end 31.876746 -293.366698)
		(width 0.18288)
		(layer "In4.Cu")
		(net "M_C_CPU1_SA_DQS_DN<2>")
	)
	(segment
		(start 78.250542 -273.445986)
		(end 78.07452 -273.445986)
		(width 0.18288)
		(layer "In4.Cu")
		(net "M_C_CPU1_SA_DQS_DN<2>")
	)
	(segment
		(start 48.772826 -294.643302)
		(end 48.058324 -294.643302)
		(width 0.18288)
		(layer "In4.Cu")
		(net "M_C_CPU1_SA_DQS_DN<2>")
	)
	(segment
		(start 91.512644 -267.871702)
		(end 91.473782 -267.8938)
		(width 0.088646)
		(layer "In4.Cu")
		(net "M_C_CPU1_SA_DQS_DN<2>")
	)
	(segment
		(start 83.401662 -269.37335)
		(end 83.341972 -269.31366)
		(width 0.088646)
		(layer "In4.Cu")
		(net "M_C_CPU1_SA_DQS_DN<2>")
	)
	(segment
		(start 82.382868 -269.31366)
		(end 82.05851 -269.638018)
		(width 0.18288)
		(layer "In4.Cu")
		(net "M_C_CPU1_SA_DQS_DN<2>")
	)
	(segment
		(start 76.346558 -275.34997)
		(end 76.170536 -275.34997)
		(width 0.18288)
		(layer "In4.Cu")
		(net "M_C_CPU1_SA_DQS_DN<2>")
	)
	(arc
		(start 87.972392 -268.080236)
		(mid 87.785194 -268.130379)
		(end 87.597996 -268.080236)
		(width 0.088646)
		(layer "In4.Cu")
		(net "M_C_CPU1_SA_DQS_DN<2>")
	)
	(arc
		(start 91.473782 -267.8938)
		(mid 91.399097 -267.924305)
		(end 91.319096 -267.934694)
		(width 0.088646)
		(layer "In4.Cu")
		(net "M_C_CPU1_SA_DQS_DN<2>")
	)
	(arc
		(start 88.906604 -268.083538)
		(mid 88.721922 -268.13049)
		(end 88.53805 -268.08049)
		(width 0.088646)
		(layer "In4.Cu")
		(net "M_C_CPU1_SA_DQS_DN<2>")
	)
	(arc
		(start 88.537796 -268.080236)
		(mid 88.255094 -268.00446)
		(end 87.972392 -268.080236)
		(width 0.088646)
		(layer "In4.Cu")
		(net "M_C_CPU1_SA_DQS_DN<2>")
	)
	(arc
		(start 87.032592 -268.080236)
		(mid 86.845394 -268.130379)
		(end 86.658196 -268.080236)
		(width 0.088646)
		(layer "In4.Cu")
		(net "M_C_CPU1_SA_DQS_DN<2>")
	)
	(arc
		(start 87.597996 -268.080236)
		(mid 87.315294 -268.00446)
		(end 87.032592 -268.080236)
		(width 0.088646)
		(layer "In4.Cu")
		(net "M_C_CPU1_SA_DQS_DN<2>")
	)
	(arc
		(start 90.417396 -268.080236)
		(mid 90.136885 -268.00459)
		(end 89.855802 -268.078204)
		(width 0.088646)
		(layer "In4.Cu")
		(net "M_C_CPU1_SA_DQS_DN<2>")
	)
	(arc
		(start 89.477596 -268.080236)
		(mid 89.197652 -268.004592)
		(end 88.917018 -268.077696)
		(width 0.088646)
		(layer "In4.Cu")
		(net "M_C_CPU1_SA_DQS_DN<2>")
	)
	(arc
		(start 85.154262 -268.079982)
		(mid 85.153754 -268.080236)
		(end 85.153246 -268.08049)
		(width 0.088646)
		(layer "In4.Cu")
		(net "M_C_CPU1_SA_DQS_DN<2>")
	)
	(arc
		(start 85.718396 -268.080236)
		(mid 85.436375 -268.004714)
		(end 85.154262 -268.079982)
		(width 0.088646)
		(layer "In4.Cu")
		(net "M_C_CPU1_SA_DQS_DN<2>")
	)
	(arc
		(start 86.092792 -268.080236)
		(mid 85.905594 -268.130379)
		(end 85.718396 -268.080236)
		(width 0.088646)
		(layer "In4.Cu")
		(net "M_C_CPU1_SA_DQS_DN<2>")
	)
	(arc
		(start 90.792046 -268.080236)
		(mid 90.604848 -268.130379)
		(end 90.41765 -268.080236)
		(width 0.088646)
		(layer "In4.Cu")
		(net "M_C_CPU1_SA_DQS_DN<2>")
	)
	(arc
		(start 86.658196 -268.080236)
		(mid 86.375494 -268.00446)
		(end 86.092792 -268.080236)
		(width 0.088646)
		(layer "In4.Cu")
		(net "M_C_CPU1_SA_DQS_DN<2>")
	)
	(arc
		(start 89.852246 -268.080236)
		(mid 89.664938 -268.130379)
		(end 89.477596 -268.080236)
		(width 0.088646)
		(layer "In4.Cu")
		(net "M_C_CPU1_SA_DQS_DN<2>")
	)
	(arc
		(start 85.153246 -268.08049)
		(mid 85.091783 -268.121237)
		(end 85.036152 -268.169644)
		(width 0.088646)
		(layer "In4.Cu")
		(net "M_C_CPU1_SA_DQS_DN<2>")
	)
	(segment
		(start 26.21534 -303.141634)
		(end 28.529026 -303.141634)
		(width 0.1016)
		(layer "F.Cu")
		(net "M_C_CPU1_SA_DQS_DN<1>")
	)
	(segment
		(start 26.204672 -303.130966)
		(end 26.21534 -303.141634)
		(width 0.101854)
		(layer "F.Cu")
		(net "M_C_CPU1_SA_DQS_DN<1>")
	)
	(segment
		(start 30.225238 -302.716692)
		(end 30.771846 -302.716692)
		(width 0.20066)
		(layer "F.Cu")
		(net "M_C_CPU1_SA_DQS_DN<1>")
	)
	(segment
		(start 28.68422 -303.141634)
		(end 28.945586 -303.403)
		(width 0.20066)
		(layer "F.Cu")
		(net "M_C_CPU1_SA_DQS_DN<1>")
	)
	(segment
		(start 28.529026 -303.141634)
		(end 28.68422 -303.141634)
		(width 0.20066)
		(layer "F.Cu")
		(net "M_C_CPU1_SA_DQS_DN<1>")
	)
	(segment
		(start 24.037798 -302.977804)
		(end 24.55164 -302.977804)
		(width 0.20066)
		(layer "F.Cu")
		(net "M_C_CPU1_SA_DQS_DN<1>")
	)
	(segment
		(start 23.776686 -302.716692)
		(end 24.037798 -302.977804)
		(width 0.20066)
		(layer "F.Cu")
		(net "M_C_CPU1_SA_DQS_DN<1>")
	)
	(segment
		(start 94.833694 -269.66164)
		(end 94.833948 -270.19758)
		(width 0.20066)
		(layer "F.Cu")
		(net "M_C_CPU1_SA_DQS_DN<1>")
	)
	(segment
		(start 23.228046 -302.716692)
		(end 23.776686 -302.716692)
		(width 0.20066)
		(layer "F.Cu")
		(net "M_C_CPU1_SA_DQS_DN<1>")
	)
	(segment
		(start 25.187656 -303.403)
		(end 25.72766 -303.403)
		(width 0.20066)
		(layer "F.Cu")
		(net "M_C_CPU1_SA_DQS_DN<1>")
	)
	(segment
		(start 24.55164 -302.977804)
		(end 25.187656 -303.403)
		(width 0.20066)
		(layer "F.Cu")
		(net "M_C_CPU1_SA_DQS_DN<1>")
	)
	(segment
		(start 29.557472 -302.977804)
		(end 29.964126 -302.977804)
		(width 0.20066)
		(layer "F.Cu")
		(net "M_C_CPU1_SA_DQS_DN<1>")
	)
	(segment
		(start 25.999694 -303.130966)
		(end 26.20391 -303.130966)
		(width 0.20066)
		(layer "F.Cu")
		(net "M_C_CPU1_SA_DQS_DN<1>")
	)
	(segment
		(start 25.72766 -303.403)
		(end 25.999694 -303.130966)
		(width 0.20066)
		(layer "F.Cu")
		(net "M_C_CPU1_SA_DQS_DN<1>")
	)
	(segment
		(start 31.876746 -302.716692)
		(end 30.771846 -302.716692)
		(width 0.20066)
		(layer "F.Cu")
		(net "M_C_CPU1_SA_DQS_DN<1>")
	)
	(segment
		(start 26.20391 -303.130966)
		(end 26.204672 -303.130966)
		(width 0.101854)
		(layer "F.Cu")
		(net "M_C_CPU1_SA_DQS_DN<1>")
	)
	(segment
		(start 29.964126 -302.977804)
		(end 30.225238 -302.716692)
		(width 0.20066)
		(layer "F.Cu")
		(net "M_C_CPU1_SA_DQS_DN<1>")
	)
	(segment
		(start 28.945586 -303.403)
		(end 29.132276 -303.403)
		(width 0.20066)
		(layer "F.Cu")
		(net "M_C_CPU1_SA_DQS_DN<1>")
	)
	(segment
		(start 29.132276 -303.403)
		(end 29.557472 -302.977804)
		(width 0.20066)
		(layer "F.Cu")
		(net "M_C_CPU1_SA_DQS_DN<1>")
	)
	(segment
		(start 50.815748 -293.791386)
		(end 50.554382 -294.052752)
		(width 0.18288)
		(layer "In6.Cu")
		(net "M_C_CPU1_SA_DQS_DN<1>")
	)
	(segment
		(start 83.426046 -273.882866)
		(end 83.366356 -273.823176)
		(width 0.088646)
		(layer "In6.Cu")
		(net "M_C_CPU1_SA_DQS_DN<1>")
	)
	(segment
		(start 34.595308 -303.06264)
		(end 33.951672 -302.796956)
		(width 0.18288)
		(layer "In6.Cu")
		(net "M_C_CPU1_SA_DQS_DN<1>")
	)
	(segment
		(start 72.479916 -280.711148)
		(end 72.479916 -280.88717)
		(width 0.18288)
		(layer "In6.Cu")
		(net "M_C_CPU1_SA_DQS_DN<1>")
	)
	(segment
		(start 32.888174 -302.987964)
		(end 32.148018 -302.987964)
		(width 0.18288)
		(layer "In6.Cu")
		(net "M_C_CPU1_SA_DQS_DN<1>")
	)
	(segment
		(start 70.012052 -283.179012)
		(end 69.62394 -283.567124)
		(width 0.18288)
		(layer "In6.Cu")
		(net "M_C_CPU1_SA_DQS_DN<1>")
	)
	(segment
		(start 56.72074 -290.491164)
		(end 54.377082 -291.462206)
		(width 0.18288)
		(layer "In6.Cu")
		(net "M_C_CPU1_SA_DQS_DN<1>")
	)
	(segment
		(start 76.287884 -276.90318)
		(end 76.287884 -277.079202)
		(width 0.18288)
		(layer "In6.Cu")
		(net "M_C_CPU1_SA_DQS_DN<1>")
	)
	(segment
		(start 92.211906 -270.515842)
		(end 92.201492 -270.521938)
		(width 0.088646)
		(layer "In6.Cu")
		(net "M_C_CPU1_SA_DQS_DN<1>")
	)
	(segment
		(start 47.931324 -294.924988)
		(end 47.450502 -294.924988)
		(width 0.18288)
		(layer "In6.Cu")
		(net "M_C_CPU1_SA_DQS_DN<1>")
	)
	(segment
		(start 87.041482 -271.330674)
		(end 87.032592 -271.335754)
		(width 0.088646)
		(layer "In6.Cu")
		(net "M_C_CPU1_SA_DQS_DN<1>")
	)
	(segment
		(start 93.156278 -270.513302)
		(end 93.141546 -270.521938)
		(width 0.088646)
		(layer "In6.Cu")
		(net "M_C_CPU1_SA_DQS_DN<1>")
	)
	(segment
		(start 36.518088 -303.405032)
		(end 36.25469 -303.141634)
		(width 0.18288)
		(layer "In6.Cu")
		(net "M_C_CPU1_SA_DQS_DN<1>")
	)
	(segment
		(start 50.554382 -294.052752)
		(end 49.656492 -294.052752)
		(width 0.18288)
		(layer "In6.Cu")
		(net "M_C_CPU1_SA_DQS_DN<1>")
	)
	(segment
		(start 61.689742 -288.224214)
		(end 59.558682 -288.224214)
		(width 0.18288)
		(layer "In6.Cu")
		(net "M_C_CPU1_SA_DQS_DN<1>")
	)
	(segment
		(start 72.868028 -280.323036)
		(end 72.479916 -280.711148)
		(width 0.18288)
		(layer "In6.Cu")
		(net "M_C_CPU1_SA_DQS_DN<1>")
	)
	(segment
		(start 74.3839 -278.983186)
		(end 73.996042 -279.371044)
		(width 0.18288)
		(layer "In6.Cu")
		(net "M_C_CPU1_SA_DQS_DN<1>")
	)
	(segment
		(start 45.260768 -294.310054)
		(end 44.570396 -294.310054)
		(width 0.18288)
		(layer "In6.Cu")
		(net "M_C_CPU1_SA_DQS_DN<1>")
	)
	(segment
		(start 51.317398 -293.791386)
		(end 50.815748 -293.791386)
		(width 0.18288)
		(layer "In6.Cu")
		(net "M_C_CPU1_SA_DQS_DN<1>")
	)
	(segment
		(start 59.558682 -288.224214)
		(end 59.0296 -288.753042)
		(width 0.18288)
		(layer "In6.Cu")
		(net "M_C_CPU1_SA_DQS_DN<1>")
	)
	(segment
		(start 64.134238 -287.21177)
		(end 61.689742 -288.224214)
		(width 0.18288)
		(layer "In6.Cu")
		(net "M_C_CPU1_SA_DQS_DN<1>")
	)
	(segment
		(start 85.460332 -272.193004)
		(end 85.147658 -272.193004)
		(width 0.088646)
		(layer "In6.Cu")
		(net "M_C_CPU1_SA_DQS_DN<1>")
	)
	(segment
		(start 82.80273 -273.823176)
		(end 77.239876 -276.12721)
		(width 0.18288)
		(layer "In6.Cu")
		(net "M_C_CPU1_SA_DQS_DN<1>")
	)
	(segment
		(start 94.833948 -270.19758)
		(end 94.802198 -270.313404)
		(width 0.088646)
		(layer "In6.Cu")
		(net "M_C_CPU1_SA_DQS_DN<1>")
	)
	(segment
		(start 87.23122 -270.898112)
		(end 87.220044 -270.952722)
		(width 0.088646)
		(layer "In6.Cu")
		(net "M_C_CPU1_SA_DQS_DN<1>")
	)
	(segment
		(start 83.342988 -273.823176)
		(end 82.80273 -273.823176)
		(width 0.18288)
		(layer "In6.Cu")
		(net "M_C_CPU1_SA_DQS_DN<1>")
	)
	(segment
		(start 73.431908 -279.935178)
		(end 73.04405 -280.323036)
		(width 0.18288)
		(layer "In6.Cu")
		(net "M_C_CPU1_SA_DQS_DN<1>")
	)
	(segment
		(start 70.964044 -282.22702)
		(end 70.575932 -282.615132)
		(width 0.18288)
		(layer "In6.Cu")
		(net "M_C_CPU1_SA_DQS_DN<1>")
	)
	(segment
		(start 69.236082 -284.131004)
		(end 69.06006 -284.131004)
		(width 0.18288)
		(layer "In6.Cu")
		(net "M_C_CPU1_SA_DQS_DN<1>")
	)
	(segment
		(start 54.377082 -291.462206)
		(end 51.78806 -294.051482)
		(width 0.18288)
		(layer "In6.Cu")
		(net "M_C_CPU1_SA_DQS_DN<1>")
	)
	(segment
		(start 83.366356 -273.823176)
		(end 83.342988 -273.823176)
		(width 0.088646)
		(layer "In6.Cu")
		(net "M_C_CPU1_SA_DQS_DN<1>")
	)
	(segment
		(start 74.948034 -278.419052)
		(end 74.772012 -278.419052)
		(width 0.18288)
		(layer "In6.Cu")
		(net "M_C_CPU1_SA_DQS_DN<1>")
	)
	(segment
		(start 74.772012 -278.419052)
		(end 74.3839 -278.807164)
		(width 0.18288)
		(layer "In6.Cu")
		(net "M_C_CPU1_SA_DQS_DN<1>")
	)
	(segment
		(start 71.140066 -282.22702)
		(end 70.964044 -282.22702)
		(width 0.18288)
		(layer "In6.Cu")
		(net "M_C_CPU1_SA_DQS_DN<1>")
	)
	(segment
		(start 77.239876 -276.12721)
		(end 76.852272 -276.515068)
		(width 0.18288)
		(layer "In6.Cu")
		(net "M_C_CPU1_SA_DQS_DN<1>")
	)
	(segment
		(start 87.220044 -270.952722)
		(end 87.220044 -271.011396)
		(width 0.088646)
		(layer "In6.Cu")
		(net "M_C_CPU1_SA_DQS_DN<1>")
	)
	(segment
		(start 49.656492 -294.052752)
		(end 49.049686 -294.659558)
		(width 0.18288)
		(layer "In6.Cu")
		(net "M_C_CPU1_SA_DQS_DN<1>")
	)
	(segment
		(start 73.82002 -279.371044)
		(end 73.431908 -279.759156)
		(width 0.18288)
		(layer "In6.Cu")
		(net "M_C_CPU1_SA_DQS_DN<1>")
	)
	(segment
		(start 70.575932 -282.791154)
		(end 70.188074 -283.179012)
		(width 0.18288)
		(layer "In6.Cu")
		(net "M_C_CPU1_SA_DQS_DN<1>")
	)
	(segment
		(start 84.477098 -273.33829)
		(end 83.932522 -273.882866)
		(width 0.088646)
		(layer "In6.Cu")
		(net "M_C_CPU1_SA_DQS_DN<1>")
	)
	(segment
		(start 48.196754 -294.659558)
		(end 47.931324 -294.924988)
		(width 0.18288)
		(layer "In6.Cu")
		(net "M_C_CPU1_SA_DQS_DN<1>")
	)
	(segment
		(start 41.510458 -301.57166)
		(end 37.08527 -303.405032)
		(width 0.18288)
		(layer "In6.Cu")
		(net "M_C_CPU1_SA_DQS_DN<1>")
	)
	(segment
		(start 85.810598 -271.809718)
		(end 85.810598 -271.825212)
		(width 0.088646)
		(layer "In6.Cu")
		(net "M_C_CPU1_SA_DQS_DN<1>")
	)
	(segment
		(start 76.287884 -277.079202)
		(end 75.900026 -277.46706)
		(width 0.18288)
		(layer "In6.Cu")
		(net "M_C_CPU1_SA_DQS_DN<1>")
	)
	(segment
		(start 42.158158 -296.625264)
		(end 42.158158 -300.92396)
		(width 0.18288)
		(layer "In6.Cu")
		(net "M_C_CPU1_SA_DQS_DN<1>")
	)
	(segment
		(start 58.055256 -289.156648)
		(end 56.72074 -290.491164)
		(width 0.18288)
		(layer "In6.Cu")
		(net "M_C_CPU1_SA_DQS_DN<1>")
	)
	(segment
		(start 59.0296 -288.753042)
		(end 58.055256 -289.156648)
		(width 0.18288)
		(layer "In6.Cu")
		(net "M_C_CPU1_SA_DQS_DN<1>")
	)
	(segment
		(start 75.900026 -277.46706)
		(end 75.724004 -277.46706)
		(width 0.18288)
		(layer "In6.Cu")
		(net "M_C_CPU1_SA_DQS_DN<1>")
	)
	(segment
		(start 51.78806 -294.051482)
		(end 51.577494 -294.051482)
		(width 0.18288)
		(layer "In6.Cu")
		(net "M_C_CPU1_SA_DQS_DN<1>")
	)
	(segment
		(start 35.499294 -303.396396)
		(end 34.929064 -303.396396)
		(width 0.18288)
		(layer "In6.Cu")
		(net "M_C_CPU1_SA_DQS_DN<1>")
	)
	(segment
		(start 76.852272 -276.515068)
		(end 76.675996 -276.515068)
		(width 0.18288)
		(layer "In6.Cu")
		(net "M_C_CPU1_SA_DQS_DN<1>")
	)
	(segment
		(start 42.158158 -300.92396)
		(end 41.510458 -301.57166)
		(width 0.18288)
		(layer "In6.Cu")
		(net "M_C_CPU1_SA_DQS_DN<1>")
	)
	(segment
		(start 46.49216 -294.890952)
		(end 45.841666 -294.890952)
		(width 0.18288)
		(layer "In6.Cu")
		(net "M_C_CPU1_SA_DQS_DN<1>")
	)
	(segment
		(start 73.04405 -280.323036)
		(end 72.868028 -280.323036)
		(width 0.18288)
		(layer "In6.Cu")
		(net "M_C_CPU1_SA_DQS_DN<1>")
	)
	(segment
		(start 94.802198 -270.313404)
		(end 94.763336 -270.335502)
		(width 0.088646)
		(layer "In6.Cu")
		(net "M_C_CPU1_SA_DQS_DN<1>")
	)
	(segment
		(start 83.932522 -273.882866)
		(end 83.426046 -273.882866)
		(width 0.088646)
		(layer "In6.Cu")
		(net "M_C_CPU1_SA_DQS_DN<1>")
	)
	(segment
		(start 33.349438 -302.796956)
		(end 32.888174 -302.987964)
		(width 0.18288)
		(layer "In6.Cu")
		(net "M_C_CPU1_SA_DQS_DN<1>")
	)
	(segment
		(start 51.577494 -294.051482)
		(end 51.317398 -293.791386)
		(width 0.18288)
		(layer "In6.Cu")
		(net "M_C_CPU1_SA_DQS_DN<1>")
	)
	(segment
		(start 47.450502 -294.924988)
		(end 47.167546 -294.642032)
		(width 0.18288)
		(layer "In6.Cu")
		(net "M_C_CPU1_SA_DQS_DN<1>")
	)
	(segment
		(start 68.671948 -284.695138)
		(end 67.801236 -285.566104)
		(width 0.18288)
		(layer "In6.Cu")
		(net "M_C_CPU1_SA_DQS_DN<1>")
	)
	(segment
		(start 32.148018 -302.987964)
		(end 31.876746 -302.716692)
		(width 0.18288)
		(layer "In6.Cu")
		(net "M_C_CPU1_SA_DQS_DN<1>")
	)
	(segment
		(start 49.049686 -294.659558)
		(end 48.196754 -294.659558)
		(width 0.18288)
		(layer "In6.Cu")
		(net "M_C_CPU1_SA_DQS_DN<1>")
	)
	(segment
		(start 47.167546 -294.642032)
		(end 46.74108 -294.642032)
		(width 0.18288)
		(layer "In6.Cu")
		(net "M_C_CPU1_SA_DQS_DN<1>")
	)
	(segment
		(start 71.916036 -281.275028)
		(end 71.527924 -281.66314)
		(width 0.18288)
		(layer "In6.Cu")
		(net "M_C_CPU1_SA_DQS_DN<1>")
	)
	(segment
		(start 85.147658 -272.193004)
		(end 84.477098 -272.863564)
		(width 0.088646)
		(layer "In6.Cu")
		(net "M_C_CPU1_SA_DQS_DN<1>")
	)
	(segment
		(start 84.477098 -272.863564)
		(end 84.477098 -273.33829)
		(width 0.088646)
		(layer "In6.Cu")
		(net "M_C_CPU1_SA_DQS_DN<1>")
	)
	(segment
		(start 91.27236 -270.515842)
		(end 91.261946 -270.521938)
		(width 0.088646)
		(layer "In6.Cu")
		(net "M_C_CPU1_SA_DQS_DN<1>")
	)
	(segment
		(start 44.059602 -294.522144)
		(end 43.549062 -294.73398)
		(width 0.18288)
		(layer "In6.Cu")
		(net "M_C_CPU1_SA_DQS_DN<1>")
	)
	(segment
		(start 76.675996 -276.515068)
		(end 76.287884 -276.90318)
		(width 0.18288)
		(layer "In6.Cu")
		(net "M_C_CPU1_SA_DQS_DN<1>")
	)
	(segment
		(start 72.479916 -280.88717)
		(end 72.092058 -281.275028)
		(width 0.18288)
		(layer "In6.Cu")
		(net "M_C_CPU1_SA_DQS_DN<1>")
	)
	(segment
		(start 94.60865 -270.376396)
		(end 94.335092 -270.376396)
		(width 0.088646)
		(layer "In6.Cu")
		(net "M_C_CPU1_SA_DQS_DN<1>")
	)
	(segment
		(start 90.332306 -270.515842)
		(end 90.321892 -270.521938)
		(width 0.088646)
		(layer "In6.Cu")
		(net "M_C_CPU1_SA_DQS_DN<1>")
	)
	(segment
		(start 70.188074 -283.179012)
		(end 70.012052 -283.179012)
		(width 0.18288)
		(layer "In6.Cu")
		(net "M_C_CPU1_SA_DQS_DN<1>")
	)
	(segment
		(start 69.62394 -283.743146)
		(end 69.236082 -284.131004)
		(width 0.18288)
		(layer "In6.Cu")
		(net "M_C_CPU1_SA_DQS_DN<1>")
	)
	(segment
		(start 71.527924 -281.66314)
		(end 71.527924 -281.839162)
		(width 0.18288)
		(layer "In6.Cu")
		(net "M_C_CPU1_SA_DQS_DN<1>")
	)
	(segment
		(start 65.779904 -285.566104)
		(end 64.134238 -287.21177)
		(width 0.18288)
		(layer "In6.Cu")
		(net "M_C_CPU1_SA_DQS_DN<1>")
	)
	(segment
		(start 34.929064 -303.396396)
		(end 34.595308 -303.06264)
		(width 0.18288)
		(layer "In6.Cu")
		(net "M_C_CPU1_SA_DQS_DN<1>")
	)
	(segment
		(start 37.08527 -303.405032)
		(end 36.518088 -303.405032)
		(width 0.18288)
		(layer "In6.Cu")
		(net "M_C_CPU1_SA_DQS_DN<1>")
	)
	(segment
		(start 69.62394 -283.567124)
		(end 69.62394 -283.743146)
		(width 0.18288)
		(layer "In6.Cu")
		(net "M_C_CPU1_SA_DQS_DN<1>")
	)
	(segment
		(start 70.575932 -282.615132)
		(end 70.575932 -282.791154)
		(width 0.18288)
		(layer "In6.Cu")
		(net "M_C_CPU1_SA_DQS_DN<1>")
	)
	(segment
		(start 71.527924 -281.839162)
		(end 71.140066 -282.22702)
		(width 0.18288)
		(layer "In6.Cu")
		(net "M_C_CPU1_SA_DQS_DN<1>")
	)
	(segment
		(start 74.3839 -278.807164)
		(end 74.3839 -278.983186)
		(width 0.18288)
		(layer "In6.Cu")
		(net "M_C_CPU1_SA_DQS_DN<1>")
	)
	(segment
		(start 46.74108 -294.642032)
		(end 46.49216 -294.890952)
		(width 0.18288)
		(layer "In6.Cu")
		(net "M_C_CPU1_SA_DQS_DN<1>")
	)
	(segment
		(start 72.092058 -281.275028)
		(end 71.916036 -281.275028)
		(width 0.18288)
		(layer "In6.Cu")
		(net "M_C_CPU1_SA_DQS_DN<1>")
	)
	(segment
		(start 44.570396 -294.310054)
		(end 44.059602 -294.522144)
		(width 0.18288)
		(layer "In6.Cu")
		(net "M_C_CPU1_SA_DQS_DN<1>")
	)
	(segment
		(start 33.951672 -302.796956)
		(end 33.349438 -302.796956)
		(width 0.18288)
		(layer "In6.Cu")
		(net "M_C_CPU1_SA_DQS_DN<1>")
	)
	(segment
		(start 86.658196 -271.335754)
		(end 86.643464 -271.327118)
		(width 0.088646)
		(layer "In6.Cu")
		(net "M_C_CPU1_SA_DQS_DN<1>")
	)
	(segment
		(start 45.841666 -294.890952)
		(end 45.260768 -294.310054)
		(width 0.18288)
		(layer "In6.Cu")
		(net "M_C_CPU1_SA_DQS_DN<1>")
	)
	(segment
		(start 42.511726 -295.771062)
		(end 42.158158 -296.625264)
		(width 0.18288)
		(layer "In6.Cu")
		(net "M_C_CPU1_SA_DQS_DN<1>")
	)
	(segment
		(start 43.549062 -294.73398)
		(end 42.511726 -295.771062)
		(width 0.18288)
		(layer "In6.Cu")
		(net "M_C_CPU1_SA_DQS_DN<1>")
	)
	(segment
		(start 35.754056 -303.141634)
		(end 35.499294 -303.396396)
		(width 0.18288)
		(layer "In6.Cu")
		(net "M_C_CPU1_SA_DQS_DN<1>")
	)
	(segment
		(start 94.335092 -270.376396)
		(end 94.081854 -270.522192)
		(width 0.088646)
		(layer "In6.Cu")
		(net "M_C_CPU1_SA_DQS_DN<1>")
	)
	(segment
		(start 67.801236 -285.566104)
		(end 65.779904 -285.566104)
		(width 0.18288)
		(layer "In6.Cu")
		(net "M_C_CPU1_SA_DQS_DN<1>")
	)
	(segment
		(start 75.335892 -278.031194)
		(end 74.948034 -278.419052)
		(width 0.18288)
		(layer "In6.Cu")
		(net "M_C_CPU1_SA_DQS_DN<1>")
	)
	(segment
		(start 93.707204 -270.521938)
		(end 93.70695 -270.521938)
		(width 0.088646)
		(layer "In6.Cu")
		(net "M_C_CPU1_SA_DQS_DN<1>")
	)
	(segment
		(start 94.081854 -270.522192)
		(end 94.0816 -270.521938)
		(width 0.088646)
		(layer "In6.Cu")
		(net "M_C_CPU1_SA_DQS_DN<1>")
	)
	(segment
		(start 75.335892 -277.855172)
		(end 75.335892 -278.031194)
		(width 0.18288)
		(layer "In6.Cu")
		(net "M_C_CPU1_SA_DQS_DN<1>")
	)
	(segment
		(start 36.25469 -303.141634)
		(end 35.754056 -303.141634)
		(width 0.18288)
		(layer "In6.Cu")
		(net "M_C_CPU1_SA_DQS_DN<1>")
	)
	(segment
		(start 73.996042 -279.371044)
		(end 73.82002 -279.371044)
		(width 0.18288)
		(layer "In6.Cu")
		(net "M_C_CPU1_SA_DQS_DN<1>")
	)
	(segment
		(start 75.724004 -277.46706)
		(end 75.335892 -277.855172)
		(width 0.18288)
		(layer "In6.Cu")
		(net "M_C_CPU1_SA_DQS_DN<1>")
	)
	(segment
		(start 68.671948 -284.519116)
		(end 68.671948 -284.695138)
		(width 0.18288)
		(layer "In6.Cu")
		(net "M_C_CPU1_SA_DQS_DN<1>")
	)
	(segment
		(start 73.431908 -279.759156)
		(end 73.431908 -279.935178)
		(width 0.18288)
		(layer "In6.Cu")
		(net "M_C_CPU1_SA_DQS_DN<1>")
	)
	(segment
		(start 69.06006 -284.131004)
		(end 68.671948 -284.519116)
		(width 0.18288)
		(layer "In6.Cu")
		(net "M_C_CPU1_SA_DQS_DN<1>")
	)
	(arc
		(start 94.763336 -270.335502)
		(mid 94.688651 -270.366007)
		(end 94.60865 -270.376396)
		(width 0.088646)
		(layer "In6.Cu")
		(net "M_C_CPU1_SA_DQS_DN<1>")
	)
	(arc
		(start 93.141546 -270.521938)
		(mid 92.954348 -270.572081)
		(end 92.76715 -270.521938)
		(width 0.088646)
		(layer "In6.Cu")
		(net "M_C_CPU1_SA_DQS_DN<1>")
	)
	(arc
		(start 93.70695 -270.521938)
		(mid 93.432751 -270.446103)
		(end 93.156278 -270.513302)
		(width 0.088646)
		(layer "In6.Cu")
		(net "M_C_CPU1_SA_DQS_DN<1>")
	)
	(arc
		(start 89.947496 -270.521938)
		(mid 89.664794 -270.446162)
		(end 89.382092 -270.521938)
		(width 0.088646)
		(layer "In6.Cu")
		(net "M_C_CPU1_SA_DQS_DN<1>")
	)
	(arc
		(start 86.643464 -271.327118)
		(mid 86.366989 -271.259798)
		(end 86.092792 -271.335754)
		(width 0.088646)
		(layer "In6.Cu")
		(net "M_C_CPU1_SA_DQS_DN<1>")
	)
	(arc
		(start 92.76715 -270.521938)
		(mid 92.490337 -270.446068)
		(end 92.211906 -270.515842)
		(width 0.088646)
		(layer "In6.Cu")
		(net "M_C_CPU1_SA_DQS_DN<1>")
	)
	(arc
		(start 90.88755 -270.521938)
		(mid 90.610737 -270.446068)
		(end 90.332306 -270.515842)
		(width 0.088646)
		(layer "In6.Cu")
		(net "M_C_CPU1_SA_DQS_DN<1>")
	)
	(arc
		(start 92.201492 -270.521938)
		(mid 92.014294 -270.572081)
		(end 91.827096 -270.521938)
		(width 0.088646)
		(layer "In6.Cu")
		(net "M_C_CPU1_SA_DQS_DN<1>")
	)
	(arc
		(start 85.810598 -271.825212)
		(mid 85.762919 -272.008112)
		(end 85.632036 -272.14449)
		(width 0.088646)
		(layer "In6.Cu")
		(net "M_C_CPU1_SA_DQS_DN<1>")
	)
	(arc
		(start 87.032592 -271.335754)
		(mid 86.845394 -271.385897)
		(end 86.658196 -271.335754)
		(width 0.088646)
		(layer "In6.Cu")
		(net "M_C_CPU1_SA_DQS_DN<1>")
	)
	(arc
		(start 86.092792 -271.335754)
		(mid 85.889969 -271.535985)
		(end 85.810598 -271.809718)
		(width 0.088646)
		(layer "In6.Cu")
		(net "M_C_CPU1_SA_DQS_DN<1>")
	)
	(arc
		(start 87.220044 -271.011396)
		(mid 87.172365 -271.194296)
		(end 87.041482 -271.330674)
		(width 0.088646)
		(layer "In6.Cu")
		(net "M_C_CPU1_SA_DQS_DN<1>")
	)
	(arc
		(start 91.827096 -270.521938)
		(mid 91.550537 -270.446195)
		(end 91.27236 -270.515842)
		(width 0.088646)
		(layer "In6.Cu")
		(net "M_C_CPU1_SA_DQS_DN<1>")
	)
	(arc
		(start 85.632036 -272.14449)
		(mid 85.549549 -272.180664)
		(end 85.460332 -272.193004)
		(width 0.088646)
		(layer "In6.Cu")
		(net "M_C_CPU1_SA_DQS_DN<1>")
	)
	(arc
		(start 89.007696 -270.521938)
		(mid 88.724994 -270.446162)
		(end 88.442292 -270.521938)
		(width 0.088646)
		(layer "In6.Cu")
		(net "M_C_CPU1_SA_DQS_DN<1>")
	)
	(arc
		(start 90.321892 -270.521938)
		(mid 90.134694 -270.572081)
		(end 89.947496 -270.521938)
		(width 0.088646)
		(layer "In6.Cu")
		(net "M_C_CPU1_SA_DQS_DN<1>")
	)
	(arc
		(start 91.261946 -270.521938)
		(mid 91.074748 -270.572081)
		(end 90.88755 -270.521938)
		(width 0.088646)
		(layer "In6.Cu")
		(net "M_C_CPU1_SA_DQS_DN<1>")
	)
	(arc
		(start 94.0816 -270.521938)
		(mid 93.894402 -270.572081)
		(end 93.707204 -270.521938)
		(width 0.088646)
		(layer "In6.Cu")
		(net "M_C_CPU1_SA_DQS_DN<1>")
	)
	(arc
		(start 89.382092 -270.521938)
		(mid 89.194894 -270.572081)
		(end 89.007696 -270.521938)
		(width 0.088646)
		(layer "In6.Cu")
		(net "M_C_CPU1_SA_DQS_DN<1>")
	)
	(arc
		(start 88.067896 -270.521938)
		(mid 87.553161 -270.49573)
		(end 87.23122 -270.898112)
		(width 0.088646)
		(layer "In6.Cu")
		(net "M_C_CPU1_SA_DQS_DN<1>")
	)
	(arc
		(start 88.442292 -270.521938)
		(mid 88.255094 -270.572081)
		(end 88.067896 -270.521938)
		(width 0.088646)
		(layer "In6.Cu")
		(net "M_C_CPU1_SA_DQS_DN<1>")
	)
	(segment
		(start 29.557472 -312.327798)
		(end 29.964126 -312.327798)
		(width 0.20066)
		(layer "F.Cu")
		(net "M_C_CPU1_SA_DQS_DN<0>")
	)
	(segment
		(start 25.187656 -312.752994)
		(end 25.72766 -312.752994)
		(width 0.20066)
		(layer "F.Cu")
		(net "M_C_CPU1_SA_DQS_DN<0>")
	)
	(segment
		(start 30.225238 -312.066686)
		(end 30.771846 -312.066686)
		(width 0.20066)
		(layer "F.Cu")
		(net "M_C_CPU1_SA_DQS_DN<0>")
	)
	(segment
		(start 26.21534 -312.491628)
		(end 28.529026 -312.491628)
		(width 0.1016)
		(layer "F.Cu")
		(net "M_C_CPU1_SA_DQS_DN<0>")
	)
	(segment
		(start 26.204672 -312.48096)
		(end 26.21534 -312.491628)
		(width 0.101854)
		(layer "F.Cu")
		(net "M_C_CPU1_SA_DQS_DN<0>")
	)
	(segment
		(start 31.876746 -312.066686)
		(end 30.771846 -312.066686)
		(width 0.20066)
		(layer "F.Cu")
		(net "M_C_CPU1_SA_DQS_DN<0>")
	)
	(segment
		(start 24.037798 -312.327798)
		(end 24.55164 -312.327798)
		(width 0.20066)
		(layer "F.Cu")
		(net "M_C_CPU1_SA_DQS_DN<0>")
	)
	(segment
		(start 91.544648 -276.986492)
		(end 91.544648 -277.522178)
		(width 0.20066)
		(layer "F.Cu")
		(net "M_C_CPU1_SA_DQS_DN<0>")
	)
	(segment
		(start 26.20391 -312.48096)
		(end 26.204672 -312.48096)
		(width 0.101854)
		(layer "F.Cu")
		(net "M_C_CPU1_SA_DQS_DN<0>")
	)
	(segment
		(start 23.776686 -312.066686)
		(end 24.037798 -312.327798)
		(width 0.20066)
		(layer "F.Cu")
		(net "M_C_CPU1_SA_DQS_DN<0>")
	)
	(segment
		(start 25.999694 -312.48096)
		(end 26.20391 -312.48096)
		(width 0.20066)
		(layer "F.Cu")
		(net "M_C_CPU1_SA_DQS_DN<0>")
	)
	(segment
		(start 28.945586 -312.752994)
		(end 29.132276 -312.752994)
		(width 0.20066)
		(layer "F.Cu")
		(net "M_C_CPU1_SA_DQS_DN<0>")
	)
	(segment
		(start 28.529026 -312.491628)
		(end 28.68422 -312.491628)
		(width 0.20066)
		(layer "F.Cu")
		(net "M_C_CPU1_SA_DQS_DN<0>")
	)
	(segment
		(start 29.964126 -312.327798)
		(end 30.225238 -312.066686)
		(width 0.20066)
		(layer "F.Cu")
		(net "M_C_CPU1_SA_DQS_DN<0>")
	)
	(segment
		(start 25.72766 -312.752994)
		(end 25.999694 -312.48096)
		(width 0.20066)
		(layer "F.Cu")
		(net "M_C_CPU1_SA_DQS_DN<0>")
	)
	(segment
		(start 29.132276 -312.752994)
		(end 29.557472 -312.327798)
		(width 0.20066)
		(layer "F.Cu")
		(net "M_C_CPU1_SA_DQS_DN<0>")
	)
	(segment
		(start 91.544648 -277.522178)
		(end 91.544394 -277.522432)
		(width 0.20066)
		(layer "F.Cu")
		(net "M_C_CPU1_SA_DQS_DN<0>")
	)
	(segment
		(start 23.228046 -312.066686)
		(end 23.776686 -312.066686)
		(width 0.20066)
		(layer "F.Cu")
		(net "M_C_CPU1_SA_DQS_DN<0>")
	)
	(segment
		(start 28.68422 -312.491628)
		(end 28.945586 -312.752994)
		(width 0.20066)
		(layer "F.Cu")
		(net "M_C_CPU1_SA_DQS_DN<0>")
	)
	(segment
		(start 24.55164 -312.327798)
		(end 25.187656 -312.752994)
		(width 0.20066)
		(layer "F.Cu")
		(net "M_C_CPU1_SA_DQS_DN<0>")
	)
	(segment
		(start 73.660762 -302.141382)
		(end 73.272904 -302.52924)
		(width 0.18288)
		(layer "In4.Cu")
		(net "M_C_CPU1_SA_DQS_DN<0>")
	)
	(segment
		(start 35.52698 -312.746644)
		(end 34.999422 -312.746644)
		(width 0.18288)
		(layer "In4.Cu")
		(net "M_C_CPU1_SA_DQS_DN<0>")
	)
	(segment
		(start 69.696838 -307.84546)
		(end 69.696838 -308.021482)
		(width 0.18288)
		(layer "In4.Cu")
		(net "M_C_CPU1_SA_DQS_DN<0>")
	)
	(segment
		(start 78.032864 -297.76928)
		(end 77.856842 -297.76928)
		(width 0.18288)
		(layer "In4.Cu")
		(net "M_C_CPU1_SA_DQS_DN<0>")
	)
	(segment
		(start 47.164244 -315.041788)
		(end 46.770036 -315.041788)
		(width 0.18288)
		(layer "In4.Cu")
		(net "M_C_CPU1_SA_DQS_DN<0>")
	)
	(segment
		(start 84.94141 -285.740856)
		(end 84.919058 -285.763208)
		(width 0.088646)
		(layer "In4.Cu")
		(net "M_C_CPU1_SA_DQS_DN<0>")
	)
	(segment
		(start 90.330782 -278.65578)
		(end 90.321892 -278.66086)
		(width 0.088646)
		(layer "In4.Cu")
		(net "M_C_CPU1_SA_DQS_DN<0>")
	)
	(segment
		(start 88.451182 -283.539184)
		(end 88.442292 -283.544264)
		(width 0.088646)
		(layer "In4.Cu")
		(net "M_C_CPU1_SA_DQS_DN<0>")
	)
	(segment
		(start 41.551098 -313.653932)
		(end 39.407084 -312.76544)
		(width 0.18288)
		(layer "In4.Cu")
		(net "M_C_CPU1_SA_DQS_DN<0>")
	)
	(segment
		(start 82.203544 -288.25063)
		(end 78.420722 -297.381422)
		(width 0.18288)
		(layer "In4.Cu")
		(net "M_C_CPU1_SA_DQS_DN<0>")
	)
	(segment
		(start 39.407084 -312.76544)
		(end 36.447984 -312.76544)
		(width 0.18288)
		(layer "In4.Cu")
		(net "M_C_CPU1_SA_DQS_DN<0>")
	)
	(segment
		(start 85.508084 -285.259526)
		(end 85.025738 -285.740856)
		(width 0.088646)
		(layer "In4.Cu")
		(net "M_C_CPU1_SA_DQS_DN<0>")
	)
	(segment
		(start 77.46873 -298.157392)
		(end 77.46873 -298.333414)
		(width 0.18288)
		(layer "In4.Cu")
		(net "M_C_CPU1_SA_DQS_DN<0>")
	)
	(segment
		(start 72.70877 -302.917352)
		(end 72.70877 -303.093374)
		(width 0.18288)
		(layer "In4.Cu")
		(net "M_C_CPU1_SA_DQS_DN<0>")
	)
	(segment
		(start 67.792854 -309.749444)
		(end 67.792854 -309.925466)
		(width 0.18288)
		(layer "In4.Cu")
		(net "M_C_CPU1_SA_DQS_DN<0>")
	)
	(segment
		(start 69.696838 -308.021482)
		(end 69.30898 -308.40934)
		(width 0.18288)
		(layer "In4.Cu")
		(net "M_C_CPU1_SA_DQS_DN<0>")
	)
	(segment
		(start 69.132958 -308.40934)
		(end 68.744846 -308.797452)
		(width 0.18288)
		(layer "In4.Cu")
		(net "M_C_CPU1_SA_DQS_DN<0>")
	)
	(segment
		(start 75.564746 -300.237398)
		(end 75.176888 -300.625256)
		(width 0.18288)
		(layer "In4.Cu")
		(net "M_C_CPU1_SA_DQS_DN<0>")
	)
	(segment
		(start 90.322654 -279.640284)
		(end 90.325194 -279.641808)
		(width 0.088646)
		(layer "In4.Cu")
		(net "M_C_CPU1_SA_DQS_DN<0>")
	)
	(segment
		(start 56.796686 -313.668156)
		(end 55.795926 -313.668156)
		(width 0.18288)
		(layer "In4.Cu")
		(net "M_C_CPU1_SA_DQS_DN<0>")
	)
	(segment
		(start 75.952858 -299.673264)
		(end 75.564746 -300.061376)
		(width 0.18288)
		(layer "In4.Cu")
		(net "M_C_CPU1_SA_DQS_DN<0>")
	)
	(segment
		(start 87.981282 -284.353)
		(end 87.972392 -284.35808)
		(width 0.088646)
		(layer "In4.Cu")
		(net "M_C_CPU1_SA_DQS_DN<0>")
	)
	(segment
		(start 36.174172 -312.491628)
		(end 35.781996 -312.491628)
		(width 0.18288)
		(layer "In4.Cu")
		(net "M_C_CPU1_SA_DQS_DN<0>")
	)
	(segment
		(start 68.180966 -309.361332)
		(end 67.792854 -309.749444)
		(width 0.18288)
		(layer "In4.Cu")
		(net "M_C_CPU1_SA_DQS_DN<0>")
	)
	(segment
		(start 77.856842 -297.76928)
		(end 77.46873 -298.157392)
		(width 0.18288)
		(layer "In4.Cu")
		(net "M_C_CPU1_SA_DQS_DN<0>")
	)
	(segment
		(start 88.927178 -282.721558)
		(end 88.912446 -282.730194)
		(width 0.088646)
		(layer "In4.Cu")
		(net "M_C_CPU1_SA_DQS_DN<0>")
	)
	(segment
		(start 70.260972 -307.457348)
		(end 70.08495 -307.457348)
		(width 0.18288)
		(layer "In4.Cu")
		(net "M_C_CPU1_SA_DQS_DN<0>")
	)
	(segment
		(start 51.532536 -314.456318)
		(end 51.267868 -314.19165)
		(width 0.18288)
		(layer "In4.Cu")
		(net "M_C_CPU1_SA_DQS_DN<0>")
	)
	(segment
		(start 46.770036 -315.041788)
		(end 46.506384 -315.30544)
		(width 0.18288)
		(layer "In4.Cu")
		(net "M_C_CPU1_SA_DQS_DN<0>")
	)
	(segment
		(start 78.420722 -297.381422)
		(end 78.032864 -297.76928)
		(width 0.18288)
		(layer "In4.Cu")
		(net "M_C_CPU1_SA_DQS_DN<0>")
	)
	(segment
		(start 89.860882 -281.097482)
		(end 89.851992 -281.102562)
		(width 0.088646)
		(layer "In4.Cu")
		(net "M_C_CPU1_SA_DQS_DN<0>")
	)
	(segment
		(start 68.744846 -308.797452)
		(end 68.744846 -308.973474)
		(width 0.18288)
		(layer "In4.Cu")
		(net "M_C_CPU1_SA_DQS_DN<0>")
	)
	(segment
		(start 71.036942 -306.505356)
		(end 70.64883 -306.893468)
		(width 0.18288)
		(layer "In4.Cu")
		(net "M_C_CPU1_SA_DQS_DN<0>")
	)
	(segment
		(start 50.62347 -314.439808)
		(end 49.883568 -314.439808)
		(width 0.18288)
		(layer "In4.Cu")
		(net "M_C_CPU1_SA_DQS_DN<0>")
	)
	(segment
		(start 34.999422 -312.746644)
		(end 34.38144 -312.128662)
		(width 0.18288)
		(layer "In4.Cu")
		(net "M_C_CPU1_SA_DQS_DN<0>")
	)
	(segment
		(start 70.08495 -307.457348)
		(end 69.696838 -307.84546)
		(width 0.18288)
		(layer "In4.Cu")
		(net "M_C_CPU1_SA_DQS_DN<0>")
	)
	(segment
		(start 70.64883 -306.893468)
		(end 70.64883 -307.06949)
		(width 0.18288)
		(layer "In4.Cu")
		(net "M_C_CPU1_SA_DQS_DN<0>")
	)
	(segment
		(start 51.267868 -314.19165)
		(end 50.871628 -314.19165)
		(width 0.18288)
		(layer "In4.Cu")
		(net "M_C_CPU1_SA_DQS_DN<0>")
	)
	(segment
		(start 47.419514 -315.297058)
		(end 47.164244 -315.041788)
		(width 0.18288)
		(layer "In4.Cu")
		(net "M_C_CPU1_SA_DQS_DN<0>")
	)
	(segment
		(start 50.871628 -314.19165)
		(end 50.62347 -314.439808)
		(width 0.18288)
		(layer "In4.Cu")
		(net "M_C_CPU1_SA_DQS_DN<0>")
	)
	(segment
		(start 44.767754 -314.497466)
		(end 43.923966 -313.653932)
		(width 0.18288)
		(layer "In4.Cu")
		(net "M_C_CPU1_SA_DQS_DN<0>")
	)
	(segment
		(start 68.744846 -308.973474)
		(end 68.356988 -309.361332)
		(width 0.18288)
		(layer "In4.Cu")
		(net "M_C_CPU1_SA_DQS_DN<0>")
	)
	(segment
		(start 91.512644 -277.638256)
		(end 91.473782 -277.660354)
		(width 0.088646)
		(layer "In4.Cu")
		(net "M_C_CPU1_SA_DQS_DN<0>")
	)
	(segment
		(start 84.480146 -286.20212)
		(end 84.252054 -286.20212)
		(width 0.18288)
		(layer "In4.Cu")
		(net "M_C_CPU1_SA_DQS_DN<0>")
	)
	(segment
		(start 49.883568 -314.439808)
		(end 49.026318 -315.297058)
		(width 0.18288)
		(layer "In4.Cu")
		(net "M_C_CPU1_SA_DQS_DN<0>")
	)
	(segment
		(start 75.176888 -300.625256)
		(end 75.000866 -300.625256)
		(width 0.18288)
		(layer "In4.Cu")
		(net "M_C_CPU1_SA_DQS_DN<0>")
	)
	(segment
		(start 35.781996 -312.491628)
		(end 35.52698 -312.746644)
		(width 0.18288)
		(layer "In4.Cu")
		(net "M_C_CPU1_SA_DQS_DN<0>")
	)
	(segment
		(start 71.212964 -306.505356)
		(end 71.036942 -306.505356)
		(width 0.18288)
		(layer "In4.Cu")
		(net "M_C_CPU1_SA_DQS_DN<0>")
	)
	(segment
		(start 71.600822 -304.201576)
		(end 71.600822 -306.117498)
		(width 0.18288)
		(layer "In4.Cu")
		(net "M_C_CPU1_SA_DQS_DN<0>")
	)
	(segment
		(start 77.46873 -298.333414)
		(end 77.080872 -298.721272)
		(width 0.18288)
		(layer "In4.Cu")
		(net "M_C_CPU1_SA_DQS_DN<0>")
	)
	(segment
		(start 45.550582 -314.821824)
		(end 44.767754 -314.497466)
		(width 0.18288)
		(layer "In4.Cu")
		(net "M_C_CPU1_SA_DQS_DN<0>")
	)
	(segment
		(start 77.080872 -298.721272)
		(end 76.90485 -298.721272)
		(width 0.18288)
		(layer "In4.Cu")
		(net "M_C_CPU1_SA_DQS_DN<0>")
	)
	(segment
		(start 34.38144 -312.128662)
		(end 32.65932 -312.128662)
		(width 0.18288)
		(layer "In4.Cu")
		(net "M_C_CPU1_SA_DQS_DN<0>")
	)
	(segment
		(start 55.795926 -313.668156)
		(end 55.007764 -314.456318)
		(width 0.18288)
		(layer "In4.Cu")
		(net "M_C_CPU1_SA_DQS_DN<0>")
	)
	(segment
		(start 64.470026 -311.94375)
		(end 58.521092 -311.94375)
		(width 0.18288)
		(layer "In4.Cu")
		(net "M_C_CPU1_SA_DQS_DN<0>")
	)
	(segment
		(start 32.65932 -312.128662)
		(end 32.457136 -312.330846)
		(width 0.18288)
		(layer "In4.Cu")
		(net "M_C_CPU1_SA_DQS_DN<0>")
	)
	(segment
		(start 90.039444 -279.140412)
		(end 90.039444 -279.160224)
		(width 0.088646)
		(layer "In4.Cu")
		(net "M_C_CPU1_SA_DQS_DN<0>")
	)
	(segment
		(start 88.442292 -283.544264)
		(end 88.436196 -283.54782)
		(width 0.088646)
		(layer "In4.Cu")
		(net "M_C_CPU1_SA_DQS_DN<0>")
	)
	(segment
		(start 73.272904 -302.52924)
		(end 73.096882 -302.52924)
		(width 0.18288)
		(layer "In4.Cu")
		(net "M_C_CPU1_SA_DQS_DN<0>")
	)
	(segment
		(start 74.048874 -301.577248)
		(end 73.660762 -301.96536)
		(width 0.18288)
		(layer "In4.Cu")
		(net "M_C_CPU1_SA_DQS_DN<0>")
	)
	(segment
		(start 89.569544 -281.591766)
		(end 89.569544 -281.59202)
		(width 0.088646)
		(layer "In4.Cu")
		(net "M_C_CPU1_SA_DQS_DN<0>")
	)
	(segment
		(start 69.30898 -308.40934)
		(end 69.132958 -308.40934)
		(width 0.18288)
		(layer "In4.Cu")
		(net "M_C_CPU1_SA_DQS_DN<0>")
	)
	(segment
		(start 90.321892 -279.639776)
		(end 90.322654 -279.640284)
		(width 0.088646)
		(layer "In4.Cu")
		(net "M_C_CPU1_SA_DQS_DN<0>")
	)
	(segment
		(start 73.096882 -302.52924)
		(end 72.70877 -302.917352)
		(width 0.18288)
		(layer "In4.Cu")
		(net "M_C_CPU1_SA_DQS_DN<0>")
	)
	(segment
		(start 88.629744 -283.205682)
		(end 88.629744 -283.219906)
		(width 0.088646)
		(layer "In4.Cu")
		(net "M_C_CPU1_SA_DQS_DN<0>")
	)
	(segment
		(start 90.039444 -280.759662)
		(end 90.039444 -280.778204)
		(width 0.088646)
		(layer "In4.Cu")
		(net "M_C_CPU1_SA_DQS_DN<0>")
	)
	(segment
		(start 76.516738 -299.109384)
		(end 76.516738 -299.285406)
		(width 0.18288)
		(layer "In4.Cu")
		(net "M_C_CPU1_SA_DQS_DN<0>")
	)
	(segment
		(start 73.660762 -301.96536)
		(end 73.660762 -302.141382)
		(width 0.18288)
		(layer "In4.Cu")
		(net "M_C_CPU1_SA_DQS_DN<0>")
	)
	(segment
		(start 89.852246 -282.081478)
		(end 89.852246 -282.081732)
		(width 0.088646)
		(layer "In4.Cu")
		(net "M_C_CPU1_SA_DQS_DN<0>")
	)
	(segment
		(start 71.600822 -306.117498)
		(end 71.212964 -306.505356)
		(width 0.18288)
		(layer "In4.Cu")
		(net "M_C_CPU1_SA_DQS_DN<0>")
	)
	(segment
		(start 91.544394 -277.522432)
		(end 91.512644 -277.638256)
		(width 0.088646)
		(layer "In4.Cu")
		(net "M_C_CPU1_SA_DQS_DN<0>")
	)
	(segment
		(start 74.612754 -301.18939)
		(end 74.224896 -301.577248)
		(width 0.18288)
		(layer "In4.Cu")
		(net "M_C_CPU1_SA_DQS_DN<0>")
	)
	(segment
		(start 84.252054 -286.20212)
		(end 82.203544 -288.25063)
		(width 0.18288)
		(layer "In4.Cu")
		(net "M_C_CPU1_SA_DQS_DN<0>")
	)
	(segment
		(start 70.64883 -307.06949)
		(end 70.260972 -307.457348)
		(width 0.18288)
		(layer "In4.Cu")
		(net "M_C_CPU1_SA_DQS_DN<0>")
	)
	(segment
		(start 87.689944 -284.837632)
		(end 87.689944 -284.847538)
		(width 0.088646)
		(layer "In4.Cu")
		(net "M_C_CPU1_SA_DQS_DN<0>")
	)
	(segment
		(start 90.325194 -279.641808)
		(end 90.330782 -279.644856)
		(width 0.088646)
		(layer "In4.Cu")
		(net "M_C_CPU1_SA_DQS_DN<0>")
	)
	(segment
		(start 36.447984 -312.76544)
		(end 36.174172 -312.491628)
		(width 0.18288)
		(layer "In4.Cu")
		(net "M_C_CPU1_SA_DQS_DN<0>")
	)
	(segment
		(start 76.516738 -299.285406)
		(end 76.12888 -299.673264)
		(width 0.18288)
		(layer "In4.Cu")
		(net "M_C_CPU1_SA_DQS_DN<0>")
	)
	(segment
		(start 72.70877 -303.093374)
		(end 71.600822 -304.201576)
		(width 0.18288)
		(layer "In4.Cu")
		(net "M_C_CPU1_SA_DQS_DN<0>")
	)
	(segment
		(start 74.224896 -301.577248)
		(end 74.048874 -301.577248)
		(width 0.18288)
		(layer "In4.Cu")
		(net "M_C_CPU1_SA_DQS_DN<0>")
	)
	(segment
		(start 76.90485 -298.721272)
		(end 76.516738 -299.109384)
		(width 0.18288)
		(layer "In4.Cu")
		(net "M_C_CPU1_SA_DQS_DN<0>")
	)
	(segment
		(start 90.330782 -280.283412)
		(end 90.321892 -280.288492)
		(width 0.088646)
		(layer "In4.Cu")
		(net "M_C_CPU1_SA_DQS_DN<0>")
	)
	(segment
		(start 32.457136 -312.330846)
		(end 32.140906 -312.330846)
		(width 0.18288)
		(layer "In4.Cu")
		(net "M_C_CPU1_SA_DQS_DN<0>")
	)
	(segment
		(start 46.506384 -315.30544)
		(end 46.033944 -315.30544)
		(width 0.18288)
		(layer "In4.Cu")
		(net "M_C_CPU1_SA_DQS_DN<0>")
	)
	(segment
		(start 84.919058 -285.763208)
		(end 84.480146 -286.20212)
		(width 0.18288)
		(layer "In4.Cu")
		(net "M_C_CPU1_SA_DQS_DN<0>")
	)
	(segment
		(start 74.612754 -301.013368)
		(end 74.612754 -301.18939)
		(width 0.18288)
		(layer "In4.Cu")
		(net "M_C_CPU1_SA_DQS_DN<0>")
	)
	(segment
		(start 46.033944 -315.30544)
		(end 45.550582 -314.821824)
		(width 0.18288)
		(layer "In4.Cu")
		(net "M_C_CPU1_SA_DQS_DN<0>")
	)
	(segment
		(start 89.84615 -282.077922)
		(end 89.852246 -282.081478)
		(width 0.088646)
		(layer "In4.Cu")
		(net "M_C_CPU1_SA_DQS_DN<0>")
	)
	(segment
		(start 75.564746 -300.061376)
		(end 75.564746 -300.237398)
		(width 0.18288)
		(layer "In4.Cu")
		(net "M_C_CPU1_SA_DQS_DN<0>")
	)
	(segment
		(start 55.007764 -314.456318)
		(end 51.532536 -314.456318)
		(width 0.18288)
		(layer "In4.Cu")
		(net "M_C_CPU1_SA_DQS_DN<0>")
	)
	(segment
		(start 32.140906 -312.330846)
		(end 31.876746 -312.066686)
		(width 0.18288)
		(layer "In4.Cu")
		(net "M_C_CPU1_SA_DQS_DN<0>")
	)
	(segment
		(start 90.509344 -278.322278)
		(end 90.509344 -278.336502)
		(width 0.088646)
		(layer "In4.Cu")
		(net "M_C_CPU1_SA_DQS_DN<0>")
	)
	(segment
		(start 90.790522 -277.848314)
		(end 90.792046 -277.84679)
		(width 0.088646)
		(layer "In4.Cu")
		(net "M_C_CPU1_SA_DQS_DN<0>")
	)
	(segment
		(start 67.792854 -309.925466)
		(end 66.697098 -311.021222)
		(width 0.18288)
		(layer "In4.Cu")
		(net "M_C_CPU1_SA_DQS_DN<0>")
	)
	(segment
		(start 76.12888 -299.673264)
		(end 75.952858 -299.673264)
		(width 0.18288)
		(layer "In4.Cu")
		(net "M_C_CPU1_SA_DQS_DN<0>")
	)
	(segment
		(start 75.000866 -300.625256)
		(end 74.612754 -301.013368)
		(width 0.18288)
		(layer "In4.Cu")
		(net "M_C_CPU1_SA_DQS_DN<0>")
	)
	(segment
		(start 66.697098 -311.021222)
		(end 64.470026 -311.94375)
		(width 0.18288)
		(layer "In4.Cu")
		(net "M_C_CPU1_SA_DQS_DN<0>")
	)
	(segment
		(start 49.026318 -315.297058)
		(end 47.419514 -315.297058)
		(width 0.18288)
		(layer "In4.Cu")
		(net "M_C_CPU1_SA_DQS_DN<0>")
	)
	(segment
		(start 85.025738 -285.740856)
		(end 84.94141 -285.740856)
		(width 0.088646)
		(layer "In4.Cu")
		(net "M_C_CPU1_SA_DQS_DN<0>")
	)
	(segment
		(start 87.511382 -285.166816)
		(end 87.502492 -285.171896)
		(width 0.088646)
		(layer "In4.Cu")
		(net "M_C_CPU1_SA_DQS_DN<0>")
	)
	(segment
		(start 58.521092 -311.94375)
		(end 56.796686 -313.668156)
		(width 0.18288)
		(layer "In4.Cu")
		(net "M_C_CPU1_SA_DQS_DN<0>")
	)
	(segment
		(start 43.923966 -313.653932)
		(end 41.551098 -313.653932)
		(width 0.18288)
		(layer "In4.Cu")
		(net "M_C_CPU1_SA_DQS_DN<0>")
	)
	(segment
		(start 68.356988 -309.361332)
		(end 68.180966 -309.361332)
		(width 0.18288)
		(layer "In4.Cu")
		(net "M_C_CPU1_SA_DQS_DN<0>")
	)
	(segment
		(start 89.852246 -282.72994)
		(end 89.852246 -282.730194)
		(width 0.088646)
		(layer "In4.Cu")
		(net "M_C_CPU1_SA_DQS_DN<0>")
	)
	(arc
		(start 90.321892 -278.66086)
		(mid 90.117557 -278.863465)
		(end 90.039444 -279.140412)
		(width 0.088646)
		(layer "In4.Cu")
		(net "M_C_CPU1_SA_DQS_DN<0>")
	)
	(arc
		(start 88.436196 -283.54782)
		(mid 88.233783 -283.754233)
		(end 88.159844 -284.033722)
		(width 0.088646)
		(layer "In4.Cu")
		(net "M_C_CPU1_SA_DQS_DN<0>")
	)
	(arc
		(start 89.852246 -282.730194)
		(mid 89.665048 -282.780337)
		(end 89.47785 -282.730194)
		(width 0.088646)
		(layer "In4.Cu")
		(net "M_C_CPU1_SA_DQS_DN<0>")
	)
	(arc
		(start 90.321892 -280.288492)
		(mid 90.119606 -280.487473)
		(end 90.039444 -280.759662)
		(width 0.088646)
		(layer "In4.Cu")
		(net "M_C_CPU1_SA_DQS_DN<0>")
	)
	(arc
		(start 87.972392 -284.35808)
		(mid 87.768057 -284.560685)
		(end 87.689944 -284.837632)
		(width 0.088646)
		(layer "In4.Cu")
		(net "M_C_CPU1_SA_DQS_DN<0>")
	)
	(arc
		(start 87.502492 -285.171896)
		(mid 87.315294 -285.222039)
		(end 87.128096 -285.171896)
		(width 0.088646)
		(layer "In4.Cu")
		(net "M_C_CPU1_SA_DQS_DN<0>")
	)
	(arc
		(start 90.792046 -277.84679)
		(mid 90.588565 -278.047594)
		(end 90.509344 -278.322278)
		(width 0.088646)
		(layer "In4.Cu")
		(net "M_C_CPU1_SA_DQS_DN<0>")
	)
	(arc
		(start 88.159844 -284.033722)
		(mid 88.112165 -284.216622)
		(end 87.981282 -284.353)
		(width 0.088646)
		(layer "In4.Cu")
		(net "M_C_CPU1_SA_DQS_DN<0>")
	)
	(arc
		(start 85.983826 -285.101792)
		(mid 85.79751 -285.106699)
		(end 85.622892 -285.171896)
		(width 0.088646)
		(layer "In4.Cu")
		(net "M_C_CPU1_SA_DQS_DN<0>")
	)
	(arc
		(start 88.912446 -282.730194)
		(mid 88.708965 -282.930998)
		(end 88.629744 -283.205682)
		(width 0.088646)
		(layer "In4.Cu")
		(net "M_C_CPU1_SA_DQS_DN<0>")
	)
	(arc
		(start 91.250262 -277.719282)
		(mid 91.011532 -277.752224)
		(end 90.790522 -277.848314)
		(width 0.088646)
		(layer "In4.Cu")
		(net "M_C_CPU1_SA_DQS_DN<0>")
	)
	(arc
		(start 89.47785 -282.730194)
		(mid 89.203621 -282.654269)
		(end 88.927178 -282.721558)
		(width 0.088646)
		(layer "In4.Cu")
		(net "M_C_CPU1_SA_DQS_DN<0>")
	)
	(arc
		(start 91.473782 -277.660354)
		(mid 91.417091 -277.687505)
		(end 91.357196 -277.706582)
		(width 0.088646)
		(layer "In4.Cu")
		(net "M_C_CPU1_SA_DQS_DN<0>")
	)
	(arc
		(start 90.330782 -279.644856)
		(mid 90.509379 -279.964134)
		(end 90.330782 -280.283412)
		(width 0.088646)
		(layer "In4.Cu")
		(net "M_C_CPU1_SA_DQS_DN<0>")
	)
	(arc
		(start 90.509344 -278.336502)
		(mid 90.461665 -278.519402)
		(end 90.330782 -278.65578)
		(width 0.088646)
		(layer "In4.Cu")
		(net "M_C_CPU1_SA_DQS_DN<0>")
	)
	(arc
		(start 88.629744 -283.219906)
		(mid 88.582065 -283.402806)
		(end 88.451182 -283.539184)
		(width 0.088646)
		(layer "In4.Cu")
		(net "M_C_CPU1_SA_DQS_DN<0>")
	)
	(arc
		(start 86.562692 -285.171896)
		(mid 86.375494 -285.222039)
		(end 86.188296 -285.171896)
		(width 0.088646)
		(layer "In4.Cu")
		(net "M_C_CPU1_SA_DQS_DN<0>")
	)
	(arc
		(start 89.851992 -281.102562)
		(mid 89.645232 -281.309325)
		(end 89.569544 -281.591766)
		(width 0.088646)
		(layer "In4.Cu")
		(net "M_C_CPU1_SA_DQS_DN<0>")
	)
	(arc
		(start 90.039444 -279.160224)
		(mid 90.117555 -279.437173)
		(end 90.321892 -279.639776)
		(width 0.088646)
		(layer "In4.Cu")
		(net "M_C_CPU1_SA_DQS_DN<0>")
	)
	(arc
		(start 90.039444 -280.778204)
		(mid 89.991765 -280.961104)
		(end 89.860882 -281.097482)
		(width 0.088646)
		(layer "In4.Cu")
		(net "M_C_CPU1_SA_DQS_DN<0>")
	)
	(arc
		(start 91.357196 -277.706582)
		(mid 91.304107 -277.716113)
		(end 91.250262 -277.719282)
		(width 0.088646)
		(layer "In4.Cu")
		(net "M_C_CPU1_SA_DQS_DN<0>")
	)
	(arc
		(start 89.852246 -282.081732)
		(mid 89.989386 -282.218671)
		(end 90.039698 -282.405836)
		(width 0.088646)
		(layer "In4.Cu")
		(net "M_C_CPU1_SA_DQS_DN<0>")
	)
	(arc
		(start 87.128096 -285.171896)
		(mid 86.845394 -285.09612)
		(end 86.562692 -285.171896)
		(width 0.088646)
		(layer "In4.Cu")
		(net "M_C_CPU1_SA_DQS_DN<0>")
	)
	(arc
		(start 85.622892 -285.171896)
		(mid 85.562619 -285.211952)
		(end 85.508084 -285.259526)
		(width 0.088646)
		(layer "In4.Cu")
		(net "M_C_CPU1_SA_DQS_DN<0>")
	)
	(arc
		(start 90.039698 -282.405836)
		(mid 89.989405 -282.593012)
		(end 89.852246 -282.72994)
		(width 0.088646)
		(layer "In4.Cu")
		(net "M_C_CPU1_SA_DQS_DN<0>")
	)
	(arc
		(start 86.188296 -285.171896)
		(mid 86.089445 -285.126971)
		(end 85.983826 -285.101792)
		(width 0.088646)
		(layer "In4.Cu")
		(net "M_C_CPU1_SA_DQS_DN<0>")
	)
	(arc
		(start 87.689944 -284.847538)
		(mid 87.642265 -285.030438)
		(end 87.511382 -285.166816)
		(width 0.088646)
		(layer "In4.Cu")
		(net "M_C_CPU1_SA_DQS_DN<0>")
	)
	(arc
		(start 89.569544 -281.59202)
		(mid 89.643535 -281.871586)
		(end 89.84615 -282.077922)
		(width 0.088646)
		(layer "In4.Cu")
		(net "M_C_CPU1_SA_DQS_DN<0>")
	)
	(segment
		(start 26.20391 -304.832766)
		(end 26.2128 -304.841656)
		(width 0.1016)
		(layer "F.Cu")
		(net "M_C_CPU1_SA_DQ<9>")
	)
	(segment
		(start 29.13253 -305.266598)
		(end 30.771846 -305.266598)
		(width 0.20066)
		(layer "F.Cu")
		(net "M_C_CPU1_SA_DQ<9>")
	)
	(segment
		(start 24.773636 -305.477926)
		(end 25.27808 -305.477926)
		(width 0.20066)
		(layer "F.Cu")
		(net "M_C_CPU1_SA_DQ<9>")
	)
	(segment
		(start 28.198318 -304.841656)
		(end 28.529026 -304.841656)
		(width 0.101854)
		(layer "F.Cu")
		(net "M_C_CPU1_SA_DQ<9>")
	)
	(segment
		(start 31.876746 -305.266598)
		(end 30.771846 -305.266598)
		(width 0.20066)
		(layer "F.Cu")
		(net "M_C_CPU1_SA_DQ<9>")
	)
	(segment
		(start 25.432512 -305.323494)
		(end 25.432512 -304.995326)
		(width 0.20066)
		(layer "F.Cu")
		(net "M_C_CPU1_SA_DQ<9>")
	)
	(segment
		(start 23.228046 -305.266598)
		(end 24.562308 -305.266598)
		(width 0.20066)
		(layer "F.Cu")
		(net "M_C_CPU1_SA_DQ<9>")
	)
	(segment
		(start 28.529026 -304.841656)
		(end 28.707588 -304.841656)
		(width 0.20066)
		(layer "F.Cu")
		(net "M_C_CPU1_SA_DQ<9>")
	)
	(segment
		(start 26.2128 -304.841656)
		(end 28.198318 -304.841656)
		(width 0.1016)
		(layer "F.Cu")
		(net "M_C_CPU1_SA_DQ<9>")
	)
	(segment
		(start 28.707588 -304.841656)
		(end 29.13253 -305.266598)
		(width 0.20066)
		(layer "F.Cu")
		(net "M_C_CPU1_SA_DQ<9>")
	)
	(segment
		(start 25.27808 -305.477926)
		(end 25.432512 -305.323494)
		(width 0.20066)
		(layer "F.Cu")
		(net "M_C_CPU1_SA_DQ<9>")
	)
	(segment
		(start 25.595072 -304.832766)
		(end 26.20391 -304.832766)
		(width 0.20066)
		(layer "F.Cu")
		(net "M_C_CPU1_SA_DQ<9>")
	)
	(segment
		(start 25.432512 -304.995326)
		(end 25.595072 -304.832766)
		(width 0.20066)
		(layer "F.Cu")
		(net "M_C_CPU1_SA_DQ<9>")
	)
	(segment
		(start 24.562308 -305.266598)
		(end 24.773636 -305.477926)
		(width 0.20066)
		(layer "F.Cu")
		(net "M_C_CPU1_SA_DQ<9>")
	)
	(arc
		(start 95.303848 -270.475456)
		(mid 95.303784 -270.743426)
		(end 95.303594 -271.011396)
		(width 0.20066)
		(layer "F.Cu")
		(net "M_C_CPU1_SA_DQ<9>")
	)
	(segment
		(start 32.301942 -305.691794)
		(end 31.876746 -305.266598)
		(width 0.18288)
		(layer "In6.Cu")
		(net "M_C_CPU1_SA_DQ<9>")
	)
	(segment
		(start 46.199044 -298.271692)
		(end 45.825664 -298.271692)
		(width 0.18288)
		(layer "In6.Cu")
		(net "M_C_CPU1_SA_DQ<9>")
	)
	(segment
		(start 88.067896 -271.500854)
		(end 88.059006 -271.505934)
		(width 0.088646)
		(layer "In6.Cu")
		(net "M_C_CPU1_SA_DQ<9>")
	)
	(segment
		(start 94.73565 -271.448276)
		(end 94.64675 -271.500854)
		(width 0.088646)
		(layer "In6.Cu")
		(net "M_C_CPU1_SA_DQ<9>")
	)
	(segment
		(start 86.194646 -273.125184)
		(end 86.18855 -273.12874)
		(width 0.088646)
		(layer "In6.Cu")
		(net "M_C_CPU1_SA_DQ<9>")
	)
	(segment
		(start 93.156278 -271.50949)
		(end 93.141546 -271.500854)
		(width 0.088646)
		(layer "In6.Cu")
		(net "M_C_CPU1_SA_DQ<9>")
	)
	(segment
		(start 37.412422 -305.691794)
		(end 32.301942 -305.691794)
		(width 0.18288)
		(layer "In6.Cu")
		(net "M_C_CPU1_SA_DQ<9>")
	)
	(segment
		(start 52.425346 -296.341546)
		(end 49.551844 -296.341546)
		(width 0.18288)
		(layer "In6.Cu")
		(net "M_C_CPU1_SA_DQ<9>")
	)
	(segment
		(start 83.342988 -275.217636)
		(end 82.892138 -275.217636)
		(width 0.18288)
		(layer "In6.Cu")
		(net "M_C_CPU1_SA_DQ<9>")
	)
	(segment
		(start 55.645812 -293.12108)
		(end 52.425346 -296.341546)
		(width 0.18288)
		(layer "In6.Cu")
		(net "M_C_CPU1_SA_DQ<9>")
	)
	(segment
		(start 45.083476 -297.191684)
		(end 44.173902 -298.101258)
		(width 0.18288)
		(layer "In6.Cu")
		(net "M_C_CPU1_SA_DQ<9>")
	)
	(segment
		(start 66.85915 -288.736786)
		(end 65.80505 -288.736786)
		(width 0.18288)
		(layer "In6.Cu")
		(net "M_C_CPU1_SA_DQ<9>")
	)
	(segment
		(start 39.092378 -304.011838)
		(end 37.412422 -305.691794)
		(width 0.18288)
		(layer "In6.Cu")
		(net "M_C_CPU1_SA_DQ<9>")
	)
	(segment
		(start 44.173902 -298.101258)
		(end 44.173902 -301.178722)
		(width 0.18288)
		(layer "In6.Cu")
		(net "M_C_CPU1_SA_DQ<9>")
	)
	(segment
		(start 45.665644 -298.111672)
		(end 45.665644 -297.351704)
		(width 0.18288)
		(layer "In6.Cu")
		(net "M_C_CPU1_SA_DQ<9>")
	)
	(segment
		(start 85.14461 -273.76628)
		(end 83.693254 -275.217636)
		(width 0.088646)
		(layer "In6.Cu")
		(net "M_C_CPU1_SA_DQ<9>")
	)
	(segment
		(start 88.452706 -271.50695)
		(end 88.442292 -271.500854)
		(width 0.088646)
		(layer "In6.Cu")
		(net "M_C_CPU1_SA_DQ<9>")
	)
	(segment
		(start 92.216478 -271.50949)
		(end 92.201746 -271.500854)
		(width 0.088646)
		(layer "In6.Cu")
		(net "M_C_CPU1_SA_DQ<9>")
	)
	(segment
		(start 82.892138 -275.217636)
		(end 78.600554 -276.995382)
		(width 0.18288)
		(layer "In6.Cu")
		(net "M_C_CPU1_SA_DQ<9>")
	)
	(segment
		(start 64.148208 -290.393628)
		(end 61.83376 -290.393628)
		(width 0.18288)
		(layer "In6.Cu")
		(net "M_C_CPU1_SA_DQ<9>")
	)
	(segment
		(start 85.637878 -273.137376)
		(end 85.623146 -273.12874)
		(width 0.088646)
		(layer "In6.Cu")
		(net "M_C_CPU1_SA_DQ<9>")
	)
	(segment
		(start 42.930318 -302.422306)
		(end 39.092378 -304.011838)
		(width 0.18288)
		(layer "In6.Cu")
		(net "M_C_CPU1_SA_DQ<9>")
	)
	(segment
		(start 45.665644 -297.351704)
		(end 45.505624 -297.191684)
		(width 0.18288)
		(layer "In6.Cu")
		(net "M_C_CPU1_SA_DQ<9>")
	)
	(segment
		(start 56.489092 -293.12108)
		(end 55.645812 -293.12108)
		(width 0.18288)
		(layer "In6.Cu")
		(net "M_C_CPU1_SA_DQ<9>")
	)
	(segment
		(start 46.359064 -297.351704)
		(end 46.359064 -298.111672)
		(width 0.18288)
		(layer "In6.Cu")
		(net "M_C_CPU1_SA_DQ<9>")
	)
	(segment
		(start 49.551844 -296.341546)
		(end 48.701706 -297.191684)
		(width 0.18288)
		(layer "In6.Cu")
		(net "M_C_CPU1_SA_DQ<9>")
	)
	(segment
		(start 85.17763 -273.25193)
		(end 85.17763 -273.686524)
		(width 0.088646)
		(layer "In6.Cu")
		(net "M_C_CPU1_SA_DQ<9>")
	)
	(segment
		(start 78.600554 -276.995382)
		(end 66.85915 -288.736786)
		(width 0.18288)
		(layer "In6.Cu")
		(net "M_C_CPU1_SA_DQ<9>")
	)
	(segment
		(start 45.825664 -298.271692)
		(end 45.665644 -298.111672)
		(width 0.18288)
		(layer "In6.Cu")
		(net "M_C_CPU1_SA_DQ<9>")
	)
	(segment
		(start 83.693254 -275.217636)
		(end 83.342988 -275.217636)
		(width 0.088646)
		(layer "In6.Cu")
		(net "M_C_CPU1_SA_DQ<9>")
	)
	(segment
		(start 91.272106 -271.50695)
		(end 91.261692 -271.500854)
		(width 0.088646)
		(layer "In6.Cu")
		(net "M_C_CPU1_SA_DQ<9>")
	)
	(segment
		(start 46.359064 -298.111672)
		(end 46.199044 -298.271692)
		(width 0.18288)
		(layer "In6.Cu")
		(net "M_C_CPU1_SA_DQ<9>")
	)
	(segment
		(start 86.65845 -272.314924)
		(end 86.64956 -272.320004)
		(width 0.088646)
		(layer "In6.Cu")
		(net "M_C_CPU1_SA_DQ<9>")
	)
	(segment
		(start 61.83376 -290.393628)
		(end 60.986162 -291.241226)
		(width 0.18288)
		(layer "In6.Cu")
		(net "M_C_CPU1_SA_DQ<9>")
	)
	(segment
		(start 87.880444 -271.825212)
		(end 87.880444 -271.843754)
		(width 0.088646)
		(layer "In6.Cu")
		(net "M_C_CPU1_SA_DQ<9>")
	)
	(segment
		(start 48.701706 -297.191684)
		(end 46.519084 -297.191684)
		(width 0.18288)
		(layer "In6.Cu")
		(net "M_C_CPU1_SA_DQ<9>")
	)
	(segment
		(start 60.986162 -291.241226)
		(end 58.368946 -291.241226)
		(width 0.18288)
		(layer "In6.Cu")
		(net "M_C_CPU1_SA_DQ<9>")
	)
	(segment
		(start 46.519084 -297.191684)
		(end 46.359064 -297.351704)
		(width 0.18288)
		(layer "In6.Cu")
		(net "M_C_CPU1_SA_DQ<9>")
	)
	(segment
		(start 58.368946 -291.241226)
		(end 56.489092 -293.12108)
		(width 0.18288)
		(layer "In6.Cu")
		(net "M_C_CPU1_SA_DQ<9>")
	)
	(segment
		(start 65.80505 -288.736786)
		(end 64.148208 -290.393628)
		(width 0.18288)
		(layer "In6.Cu")
		(net "M_C_CPU1_SA_DQ<9>")
	)
	(segment
		(start 89.39276 -271.50695)
		(end 89.382346 -271.500854)
		(width 0.088646)
		(layer "In6.Cu")
		(net "M_C_CPU1_SA_DQ<9>")
	)
	(segment
		(start 95.303594 -271.011396)
		(end 94.73565 -271.448276)
		(width 0.088646)
		(layer "In6.Cu")
		(net "M_C_CPU1_SA_DQ<9>")
	)
	(segment
		(start 45.505624 -297.191684)
		(end 45.083476 -297.191684)
		(width 0.18288)
		(layer "In6.Cu")
		(net "M_C_CPU1_SA_DQ<9>")
	)
	(segment
		(start 44.173902 -301.178722)
		(end 42.930318 -302.422306)
		(width 0.18288)
		(layer "In6.Cu")
		(net "M_C_CPU1_SA_DQ<9>")
	)
	(segment
		(start 87.04326 -272.32102)
		(end 87.032846 -272.314924)
		(width 0.088646)
		(layer "In6.Cu")
		(net "M_C_CPU1_SA_DQ<9>")
	)
	(arc
		(start 94.081346 -271.500854)
		(mid 93.894148 -271.450711)
		(end 93.70695 -271.500854)
		(width 0.088646)
		(layer "In6.Cu")
		(net "M_C_CPU1_SA_DQ<9>")
	)
	(arc
		(start 87.032846 -272.314924)
		(mid 86.845648 -272.264781)
		(end 86.65845 -272.314924)
		(width 0.088646)
		(layer "In6.Cu")
		(net "M_C_CPU1_SA_DQ<9>")
	)
	(arc
		(start 86.470998 -272.639282)
		(mid 86.397082 -272.918784)
		(end 86.194646 -273.125184)
		(width 0.088646)
		(layer "In6.Cu")
		(net "M_C_CPU1_SA_DQ<9>")
	)
	(arc
		(start 87.880444 -271.843754)
		(mid 87.800282 -272.115943)
		(end 87.597996 -272.314924)
		(width 0.088646)
		(layer "In6.Cu")
		(net "M_C_CPU1_SA_DQ<9>")
	)
	(arc
		(start 86.64956 -272.320004)
		(mid 86.518646 -272.456364)
		(end 86.470998 -272.639282)
		(width 0.088646)
		(layer "In6.Cu")
		(net "M_C_CPU1_SA_DQ<9>")
	)
	(arc
		(start 93.70695 -271.500854)
		(mid 93.432751 -271.576689)
		(end 93.156278 -271.50949)
		(width 0.088646)
		(layer "In6.Cu")
		(net "M_C_CPU1_SA_DQ<9>")
	)
	(arc
		(start 85.623146 -273.12874)
		(mid 85.435948 -273.078597)
		(end 85.24875 -273.12874)
		(width 0.088646)
		(layer "In6.Cu")
		(net "M_C_CPU1_SA_DQ<9>")
	)
	(arc
		(start 89.947496 -271.500854)
		(mid 89.670937 -271.576597)
		(end 89.39276 -271.50695)
		(width 0.088646)
		(layer "In6.Cu")
		(net "M_C_CPU1_SA_DQ<9>")
	)
	(arc
		(start 85.24875 -273.12874)
		(mid 85.196682 -273.180806)
		(end 85.17763 -273.25193)
		(width 0.088646)
		(layer "In6.Cu")
		(net "M_C_CPU1_SA_DQ<9>")
	)
	(arc
		(start 87.597996 -272.314924)
		(mid 87.321437 -272.390633)
		(end 87.04326 -272.32102)
		(width 0.088646)
		(layer "In6.Cu")
		(net "M_C_CPU1_SA_DQ<9>")
	)
	(arc
		(start 93.141546 -271.500854)
		(mid 92.954348 -271.450711)
		(end 92.76715 -271.500854)
		(width 0.088646)
		(layer "In6.Cu")
		(net "M_C_CPU1_SA_DQ<9>")
	)
	(arc
		(start 86.18855 -273.12874)
		(mid 85.914351 -273.204575)
		(end 85.637878 -273.137376)
		(width 0.088646)
		(layer "In6.Cu")
		(net "M_C_CPU1_SA_DQ<9>")
	)
	(arc
		(start 90.321892 -271.500854)
		(mid 90.134694 -271.450711)
		(end 89.947496 -271.500854)
		(width 0.088646)
		(layer "In6.Cu")
		(net "M_C_CPU1_SA_DQ<9>")
	)
	(arc
		(start 92.201746 -271.500854)
		(mid 92.014548 -271.450711)
		(end 91.82735 -271.500854)
		(width 0.088646)
		(layer "In6.Cu")
		(net "M_C_CPU1_SA_DQ<9>")
	)
	(arc
		(start 91.261692 -271.500854)
		(mid 91.074494 -271.450711)
		(end 90.887296 -271.500854)
		(width 0.088646)
		(layer "In6.Cu")
		(net "M_C_CPU1_SA_DQ<9>")
	)
	(arc
		(start 88.059006 -271.505934)
		(mid 87.928092 -271.642294)
		(end 87.880444 -271.825212)
		(width 0.088646)
		(layer "In6.Cu")
		(net "M_C_CPU1_SA_DQ<9>")
	)
	(arc
		(start 89.00795 -271.500854)
		(mid 88.731137 -271.576724)
		(end 88.452706 -271.50695)
		(width 0.088646)
		(layer "In6.Cu")
		(net "M_C_CPU1_SA_DQ<9>")
	)
	(arc
		(start 94.64675 -271.500854)
		(mid 94.364048 -271.57663)
		(end 94.081346 -271.500854)
		(width 0.088646)
		(layer "In6.Cu")
		(net "M_C_CPU1_SA_DQ<9>")
	)
	(arc
		(start 91.82735 -271.500854)
		(mid 91.550537 -271.576724)
		(end 91.272106 -271.50695)
		(width 0.088646)
		(layer "In6.Cu")
		(net "M_C_CPU1_SA_DQ<9>")
	)
	(arc
		(start 92.76715 -271.500854)
		(mid 92.492951 -271.576689)
		(end 92.216478 -271.50949)
		(width 0.088646)
		(layer "In6.Cu")
		(net "M_C_CPU1_SA_DQ<9>")
	)
	(arc
		(start 88.442292 -271.500854)
		(mid 88.255094 -271.450711)
		(end 88.067896 -271.500854)
		(width 0.088646)
		(layer "In6.Cu")
		(net "M_C_CPU1_SA_DQ<9>")
	)
	(arc
		(start 90.887296 -271.500854)
		(mid 90.604594 -271.57663)
		(end 90.321892 -271.500854)
		(width 0.088646)
		(layer "In6.Cu")
		(net "M_C_CPU1_SA_DQ<9>")
	)
	(arc
		(start 89.382346 -271.500854)
		(mid 89.195148 -271.450711)
		(end 89.00795 -271.500854)
		(width 0.088646)
		(layer "In6.Cu")
		(net "M_C_CPU1_SA_DQ<9>")
	)
	(arc
		(start 85.17763 -273.686524)
		(mid 85.169045 -273.729682)
		(end 85.14461 -273.76628)
		(width 0.088646)
		(layer "In6.Cu")
		(net "M_C_CPU1_SA_DQ<9>")
	)
	(segment
		(start 24.801068 -307.20538)
		(end 25.259792 -307.20538)
		(width 0.20066)
		(layer "F.Cu")
		(net "M_C_CPU1_SA_DQ<8>")
	)
	(segment
		(start 24.562308 -306.96662)
		(end 24.801068 -307.20538)
		(width 0.20066)
		(layer "F.Cu")
		(net "M_C_CPU1_SA_DQ<8>")
	)
	(segment
		(start 25.259792 -307.20538)
		(end 25.432512 -307.03266)
		(width 0.20066)
		(layer "F.Cu")
		(net "M_C_CPU1_SA_DQ<8>")
	)
	(segment
		(start 25.642062 -306.53355)
		(end 26.20391 -306.53355)
		(width 0.20066)
		(layer "F.Cu")
		(net "M_C_CPU1_SA_DQ<8>")
	)
	(segment
		(start 31.876746 -306.96662)
		(end 30.771846 -306.96662)
		(width 0.20066)
		(layer "F.Cu")
		(net "M_C_CPU1_SA_DQ<8>")
	)
	(segment
		(start 28.529026 -306.541678)
		(end 28.977844 -306.541678)
		(width 0.20066)
		(layer "F.Cu")
		(net "M_C_CPU1_SA_DQ<8>")
	)
	(segment
		(start 95.773748 -271.289526)
		(end 95.773748 -271.825212)
		(width 0.20066)
		(layer "F.Cu")
		(net "M_C_CPU1_SA_DQ<8>")
	)
	(segment
		(start 29.402786 -306.96662)
		(end 30.771846 -306.96662)
		(width 0.20066)
		(layer "F.Cu")
		(net "M_C_CPU1_SA_DQ<8>")
	)
	(segment
		(start 28.977844 -306.541678)
		(end 29.402786 -306.96662)
		(width 0.20066)
		(layer "F.Cu")
		(net "M_C_CPU1_SA_DQ<8>")
	)
	(segment
		(start 95.773494 -271.289272)
		(end 95.773748 -271.289526)
		(width 0.20066)
		(layer "F.Cu")
		(net "M_C_CPU1_SA_DQ<8>")
	)
	(segment
		(start 26.212038 -306.541678)
		(end 26.459942 -306.541678)
		(width 0.101854)
		(layer "F.Cu")
		(net "M_C_CPU1_SA_DQ<8>")
	)
	(segment
		(start 25.432512 -306.7431)
		(end 25.642062 -306.53355)
		(width 0.20066)
		(layer "F.Cu")
		(net "M_C_CPU1_SA_DQ<8>")
	)
	(segment
		(start 25.432512 -307.03266)
		(end 25.432512 -306.7431)
		(width 0.20066)
		(layer "F.Cu")
		(net "M_C_CPU1_SA_DQ<8>")
	)
	(segment
		(start 26.459942 -306.541678)
		(end 28.529026 -306.541678)
		(width 0.1016)
		(layer "F.Cu")
		(net "M_C_CPU1_SA_DQ<8>")
	)
	(segment
		(start 26.20391 -306.53355)
		(end 26.212038 -306.541678)
		(width 0.101854)
		(layer "F.Cu")
		(net "M_C_CPU1_SA_DQ<8>")
	)
	(segment
		(start 23.228046 -306.96662)
		(end 24.562308 -306.96662)
		(width 0.20066)
		(layer "F.Cu")
		(net "M_C_CPU1_SA_DQ<8>")
	)
	(segment
		(start 83.342988 -276.261068)
		(end 83.048602 -276.261068)
		(width 0.18288)
		(layer "In6.Cu")
		(net "M_C_CPU1_SA_DQ<8>")
	)
	(segment
		(start 60.230766 -292.972236)
		(end 59.220354 -292.972236)
		(width 0.18288)
		(layer "In6.Cu")
		(net "M_C_CPU1_SA_DQ<8>")
	)
	(segment
		(start 61.107066 -292.789356)
		(end 61.107066 -292.634416)
		(width 0.18288)
		(layer "In6.Cu")
		(net "M_C_CPU1_SA_DQ<8>")
	)
	(segment
		(start 55.295038 -295.91381)
		(end 55.295038 -296.87012)
		(width 0.18288)
		(layer "In6.Cu")
		(net "M_C_CPU1_SA_DQ<8>")
	)
	(segment
		(start 45.943012 -300.33595)
		(end 45.943012 -302.095408)
		(width 0.18288)
		(layer "In6.Cu")
		(net "M_C_CPU1_SA_DQ<8>")
	)
	(segment
		(start 92.296996 -272.314924)
		(end 92.282264 -272.32356)
		(width 0.088646)
		(layer "In6.Cu")
		(net "M_C_CPU1_SA_DQ<8>")
	)
	(segment
		(start 49.19472 -299.74159)
		(end 46.537372 -299.74159)
		(width 0.18288)
		(layer "In6.Cu")
		(net "M_C_CPU1_SA_DQ<8>")
	)
	(segment
		(start 59.220354 -292.972236)
		(end 57.051194 -295.141396)
		(width 0.18288)
		(layer "In6.Cu")
		(net "M_C_CPU1_SA_DQ<8>")
	)
	(segment
		(start 54.12359 -298.041568)
		(end 50.894742 -298.041568)
		(width 0.18288)
		(layer "In6.Cu")
		(net "M_C_CPU1_SA_DQ<8>")
	)
	(segment
		(start 86.658196 -273.942556)
		(end 86.643464 -273.951192)
		(width 0.088646)
		(layer "In6.Cu")
		(net "M_C_CPU1_SA_DQ<8>")
	)
	(segment
		(start 61.107066 -292.634416)
		(end 60.924186 -292.451536)
		(width 0.18288)
		(layer "In6.Cu")
		(net "M_C_CPU1_SA_DQ<8>")
	)
	(segment
		(start 93.236796 -272.314924)
		(end 93.222064 -272.32356)
		(width 0.088646)
		(layer "In6.Cu")
		(net "M_C_CPU1_SA_DQ<8>")
	)
	(segment
		(start 85.509608 -274.452334)
		(end 84.847938 -275.114004)
		(width 0.088646)
		(layer "In6.Cu")
		(net "M_C_CPU1_SA_DQ<8>")
	)
	(segment
		(start 45.943012 -302.095408)
		(end 43.273472 -304.764948)
		(width 0.18288)
		(layer "In6.Cu")
		(net "M_C_CPU1_SA_DQ<8>")
	)
	(segment
		(start 83.048602 -276.261068)
		(end 79.5528 -277.709122)
		(width 0.18288)
		(layer "In6.Cu")
		(net "M_C_CPU1_SA_DQ<8>")
	)
	(segment
		(start 46.537372 -299.74159)
		(end 45.943012 -300.33595)
		(width 0.18288)
		(layer "In6.Cu")
		(net "M_C_CPU1_SA_DQ<8>")
	)
	(segment
		(start 35.720528 -307.38826)
		(end 34.704274 -306.372006)
		(width 0.18288)
		(layer "In6.Cu")
		(net "M_C_CPU1_SA_DQ<8>")
	)
	(segment
		(start 89.477596 -272.314924)
		(end 89.467182 -272.32102)
		(width 0.088646)
		(layer "In6.Cu")
		(net "M_C_CPU1_SA_DQ<8>")
	)
	(segment
		(start 83.495388 -276.261068)
		(end 83.342988 -276.261068)
		(width 0.088646)
		(layer "In6.Cu")
		(net "M_C_CPU1_SA_DQ<8>")
	)
	(segment
		(start 50.894742 -298.041568)
		(end 49.19472 -299.74159)
		(width 0.18288)
		(layer "In6.Cu")
		(net "M_C_CPU1_SA_DQ<8>")
	)
	(segment
		(start 43.273472 -304.764948)
		(end 41.138602 -304.764948)
		(width 0.18288)
		(layer "In6.Cu")
		(net "M_C_CPU1_SA_DQ<8>")
	)
	(segment
		(start 60.413646 -292.789356)
		(end 60.230766 -292.972236)
		(width 0.18288)
		(layer "In6.Cu")
		(net "M_C_CPU1_SA_DQ<8>")
	)
	(segment
		(start 61.289946 -292.972236)
		(end 61.107066 -292.789356)
		(width 0.18288)
		(layer "In6.Cu")
		(net "M_C_CPU1_SA_DQ<8>")
	)
	(segment
		(start 79.5528 -277.709122)
		(end 66.827908 -290.434014)
		(width 0.18288)
		(layer "In6.Cu")
		(net "M_C_CPU1_SA_DQ<8>")
	)
	(segment
		(start 66.827908 -290.434014)
		(end 65.799462 -290.434014)
		(width 0.18288)
		(layer "In6.Cu")
		(net "M_C_CPU1_SA_DQ<8>")
	)
	(segment
		(start 64.092074 -292.141402)
		(end 63.234316 -292.141402)
		(width 0.18288)
		(layer "In6.Cu")
		(net "M_C_CPU1_SA_DQ<8>")
	)
	(segment
		(start 41.138602 -304.764948)
		(end 40.355266 -305.548284)
		(width 0.18288)
		(layer "In6.Cu")
		(net "M_C_CPU1_SA_DQ<8>")
	)
	(segment
		(start 62.403482 -292.972236)
		(end 61.289946 -292.972236)
		(width 0.18288)
		(layer "In6.Cu")
		(net "M_C_CPU1_SA_DQ<8>")
	)
	(segment
		(start 86.664292 -273.939)
		(end 86.658196 -273.942556)
		(width 0.088646)
		(layer "In6.Cu")
		(net "M_C_CPU1_SA_DQ<8>")
	)
	(segment
		(start 34.704274 -306.372006)
		(end 32.47136 -306.372006)
		(width 0.18288)
		(layer "In6.Cu")
		(net "M_C_CPU1_SA_DQ<8>")
	)
	(segment
		(start 60.413646 -292.634416)
		(end 60.413646 -292.789356)
		(width 0.18288)
		(layer "In6.Cu")
		(net "M_C_CPU1_SA_DQ<8>")
	)
	(segment
		(start 63.234316 -292.141402)
		(end 62.403482 -292.972236)
		(width 0.18288)
		(layer "In6.Cu")
		(net "M_C_CPU1_SA_DQ<8>")
	)
	(segment
		(start 36.167568 -307.38826)
		(end 35.720528 -307.38826)
		(width 0.18288)
		(layer "In6.Cu")
		(net "M_C_CPU1_SA_DQ<8>")
	)
	(segment
		(start 85.640672 -274.001992)
		(end 85.509608 -274.133056)
		(width 0.088646)
		(layer "In6.Cu")
		(net "M_C_CPU1_SA_DQ<8>")
	)
	(segment
		(start 55.295038 -296.87012)
		(end 54.12359 -298.041568)
		(width 0.18288)
		(layer "In6.Cu")
		(net "M_C_CPU1_SA_DQ<8>")
	)
	(segment
		(start 56.067452 -295.141396)
		(end 55.295038 -295.91381)
		(width 0.18288)
		(layer "In6.Cu")
		(net "M_C_CPU1_SA_DQ<8>")
	)
	(segment
		(start 65.799462 -290.434014)
		(end 64.092074 -292.141402)
		(width 0.18288)
		(layer "In6.Cu")
		(net "M_C_CPU1_SA_DQ<8>")
	)
	(segment
		(start 60.924186 -292.451536)
		(end 60.596526 -292.451536)
		(width 0.18288)
		(layer "In6.Cu")
		(net "M_C_CPU1_SA_DQ<8>")
	)
	(segment
		(start 39.273988 -305.548284)
		(end 37.67582 -307.146452)
		(width 0.18288)
		(layer "In6.Cu")
		(net "M_C_CPU1_SA_DQ<8>")
	)
	(segment
		(start 95.116396 -272.314924)
		(end 95.101664 -272.32356)
		(width 0.088646)
		(layer "In6.Cu")
		(net "M_C_CPU1_SA_DQ<8>")
	)
	(segment
		(start 95.483172 -272.223992)
		(end 95.298514 -272.24228)
		(width 0.088646)
		(layer "In6.Cu")
		(net "M_C_CPU1_SA_DQ<8>")
	)
	(segment
		(start 60.596526 -292.451536)
		(end 60.413646 -292.634416)
		(width 0.18288)
		(layer "In6.Cu")
		(net "M_C_CPU1_SA_DQ<8>")
	)
	(segment
		(start 40.355266 -305.548284)
		(end 39.273988 -305.548284)
		(width 0.18288)
		(layer "In6.Cu")
		(net "M_C_CPU1_SA_DQ<8>")
	)
	(segment
		(start 95.212662 -272.266156)
		(end 95.145352 -272.298414)
		(width 0.088646)
		(layer "In6.Cu")
		(net "M_C_CPU1_SA_DQ<8>")
	)
	(segment
		(start 57.051194 -295.141396)
		(end 56.067452 -295.141396)
		(width 0.18288)
		(layer "In6.Cu")
		(net "M_C_CPU1_SA_DQ<8>")
	)
	(segment
		(start 89.862406 -272.32102)
		(end 89.851992 -272.314924)
		(width 0.088646)
		(layer "In6.Cu")
		(net "M_C_CPU1_SA_DQ<8>")
	)
	(segment
		(start 94.176596 -272.314924)
		(end 94.161864 -272.32356)
		(width 0.088646)
		(layer "In6.Cu")
		(net "M_C_CPU1_SA_DQ<8>")
	)
	(segment
		(start 90.80246 -272.32102)
		(end 90.792046 -272.314924)
		(width 0.088646)
		(layer "In6.Cu")
		(net "M_C_CPU1_SA_DQ<8>")
	)
	(segment
		(start 95.571056 -272.19275)
		(end 95.5675 -272.195036)
		(width 0.088646)
		(layer "In6.Cu")
		(net "M_C_CPU1_SA_DQ<8>")
	)
	(segment
		(start 37.67582 -307.146452)
		(end 36.409376 -307.146452)
		(width 0.18288)
		(layer "In6.Cu")
		(net "M_C_CPU1_SA_DQ<8>")
	)
	(segment
		(start 86.940898 -273.444462)
		(end 86.940898 -273.453098)
		(width 0.088646)
		(layer "In6.Cu")
		(net "M_C_CPU1_SA_DQ<8>")
	)
	(segment
		(start 32.47136 -306.372006)
		(end 31.876746 -306.96662)
		(width 0.18288)
		(layer "In6.Cu")
		(net "M_C_CPU1_SA_DQ<8>")
	)
	(segment
		(start 88.080088 -273.121628)
		(end 88.067896 -273.12874)
		(width 0.088646)
		(layer "In6.Cu")
		(net "M_C_CPU1_SA_DQ<8>")
	)
	(segment
		(start 85.509608 -274.133056)
		(end 85.509608 -274.452334)
		(width 0.088646)
		(layer "In6.Cu")
		(net "M_C_CPU1_SA_DQ<8>")
	)
	(segment
		(start 36.409376 -307.146452)
		(end 36.167568 -307.38826)
		(width 0.18288)
		(layer "In6.Cu")
		(net "M_C_CPU1_SA_DQ<8>")
	)
	(segment
		(start 88.53805 -272.314924)
		(end 88.52916 -272.320004)
		(width 0.088646)
		(layer "In6.Cu")
		(net "M_C_CPU1_SA_DQ<8>")
	)
	(segment
		(start 84.847938 -275.114004)
		(end 84.642452 -275.114004)
		(width 0.088646)
		(layer "In6.Cu")
		(net "M_C_CPU1_SA_DQ<8>")
	)
	(segment
		(start 95.145352 -272.298414)
		(end 95.116396 -272.314924)
		(width 0.088646)
		(layer "In6.Cu")
		(net "M_C_CPU1_SA_DQ<8>")
	)
	(segment
		(start 84.642452 -275.114004)
		(end 83.495388 -276.261068)
		(width 0.088646)
		(layer "In6.Cu")
		(net "M_C_CPU1_SA_DQ<8>")
	)
	(arc
		(start 94.550992 -272.314924)
		(mid 94.363794 -272.264781)
		(end 94.176596 -272.314924)
		(width 0.088646)
		(layer "In6.Cu")
		(net "M_C_CPU1_SA_DQ<8>")
	)
	(arc
		(start 88.350598 -272.639282)
		(mid 88.278363 -272.915806)
		(end 88.080088 -273.121628)
		(width 0.088646)
		(layer "In6.Cu")
		(net "M_C_CPU1_SA_DQ<8>")
	)
	(arc
		(start 87.128096 -273.12874)
		(mid 86.993163 -273.262094)
		(end 86.940898 -273.444462)
		(width 0.088646)
		(layer "In6.Cu")
		(net "M_C_CPU1_SA_DQ<8>")
	)
	(arc
		(start 86.940898 -273.453098)
		(mid 86.866907 -273.732664)
		(end 86.664292 -273.939)
		(width 0.088646)
		(layer "In6.Cu")
		(net "M_C_CPU1_SA_DQ<8>")
	)
	(arc
		(start 92.282264 -272.32356)
		(mid 92.005823 -272.390726)
		(end 91.731592 -272.314924)
		(width 0.088646)
		(layer "In6.Cu")
		(net "M_C_CPU1_SA_DQ<8>")
	)
	(arc
		(start 88.912446 -272.314924)
		(mid 88.725248 -272.264781)
		(end 88.53805 -272.314924)
		(width 0.088646)
		(layer "In6.Cu")
		(net "M_C_CPU1_SA_DQ<8>")
	)
	(arc
		(start 88.52916 -272.320004)
		(mid 88.398246 -272.456364)
		(end 88.350598 -272.639282)
		(width 0.088646)
		(layer "In6.Cu")
		(net "M_C_CPU1_SA_DQ<8>")
	)
	(arc
		(start 94.161864 -272.32356)
		(mid 93.885423 -272.390726)
		(end 93.611192 -272.314924)
		(width 0.088646)
		(layer "In6.Cu")
		(net "M_C_CPU1_SA_DQ<8>")
	)
	(arc
		(start 89.467182 -272.32102)
		(mid 89.189004 -272.390712)
		(end 88.912446 -272.314924)
		(width 0.088646)
		(layer "In6.Cu")
		(net "M_C_CPU1_SA_DQ<8>")
	)
	(arc
		(start 92.671392 -272.314924)
		(mid 92.484194 -272.264781)
		(end 92.296996 -272.314924)
		(width 0.088646)
		(layer "In6.Cu")
		(net "M_C_CPU1_SA_DQ<8>")
	)
	(arc
		(start 95.101664 -272.32356)
		(mid 94.825223 -272.390726)
		(end 94.550992 -272.314924)
		(width 0.088646)
		(layer "In6.Cu")
		(net "M_C_CPU1_SA_DQ<8>")
	)
	(arc
		(start 85.718396 -273.942556)
		(mid 85.677587 -273.969728)
		(end 85.640672 -274.001992)
		(width 0.088646)
		(layer "In6.Cu")
		(net "M_C_CPU1_SA_DQ<8>")
	)
	(arc
		(start 95.5675 -272.195036)
		(mid 95.527018 -272.214404)
		(end 95.483172 -272.223992)
		(width 0.088646)
		(layer "In6.Cu")
		(net "M_C_CPU1_SA_DQ<8>")
	)
	(arc
		(start 91.731592 -272.314924)
		(mid 91.544394 -272.264781)
		(end 91.357196 -272.314924)
		(width 0.088646)
		(layer "In6.Cu")
		(net "M_C_CPU1_SA_DQ<8>")
	)
	(arc
		(start 87.502492 -273.12874)
		(mid 87.315294 -273.078597)
		(end 87.128096 -273.12874)
		(width 0.088646)
		(layer "In6.Cu")
		(net "M_C_CPU1_SA_DQ<8>")
	)
	(arc
		(start 90.792046 -272.314924)
		(mid 90.604848 -272.264781)
		(end 90.41765 -272.314924)
		(width 0.088646)
		(layer "In6.Cu")
		(net "M_C_CPU1_SA_DQ<8>")
	)
	(arc
		(start 91.357196 -272.314924)
		(mid 91.080637 -272.390633)
		(end 90.80246 -272.32102)
		(width 0.088646)
		(layer "In6.Cu")
		(net "M_C_CPU1_SA_DQ<8>")
	)
	(arc
		(start 90.41765 -272.314924)
		(mid 90.140837 -272.39076)
		(end 89.862406 -272.32102)
		(width 0.088646)
		(layer "In6.Cu")
		(net "M_C_CPU1_SA_DQ<8>")
	)
	(arc
		(start 93.222064 -272.32356)
		(mid 92.945623 -272.390726)
		(end 92.671392 -272.314924)
		(width 0.088646)
		(layer "In6.Cu")
		(net "M_C_CPU1_SA_DQ<8>")
	)
	(arc
		(start 93.611192 -272.314924)
		(mid 93.423994 -272.264781)
		(end 93.236796 -272.314924)
		(width 0.088646)
		(layer "In6.Cu")
		(net "M_C_CPU1_SA_DQ<8>")
	)
	(arc
		(start 88.067896 -273.12874)
		(mid 87.785194 -273.204516)
		(end 87.502492 -273.12874)
		(width 0.088646)
		(layer "In6.Cu")
		(net "M_C_CPU1_SA_DQ<8>")
	)
	(arc
		(start 86.643464 -273.951192)
		(mid 86.366989 -274.018512)
		(end 86.092792 -273.942556)
		(width 0.088646)
		(layer "In6.Cu")
		(net "M_C_CPU1_SA_DQ<8>")
	)
	(arc
		(start 95.298514 -272.24228)
		(mid 95.254559 -272.250516)
		(end 95.212662 -272.266156)
		(width 0.088646)
		(layer "In6.Cu")
		(net "M_C_CPU1_SA_DQ<8>")
	)
	(arc
		(start 89.851992 -272.314924)
		(mid 89.664794 -272.264781)
		(end 89.477596 -272.314924)
		(width 0.088646)
		(layer "In6.Cu")
		(net "M_C_CPU1_SA_DQ<8>")
	)
	(arc
		(start 86.092792 -273.942556)
		(mid 85.905594 -273.892413)
		(end 85.718396 -273.942556)
		(width 0.088646)
		(layer "In6.Cu")
		(net "M_C_CPU1_SA_DQ<8>")
	)
	(arc
		(start 95.773748 -271.825212)
		(mid 95.719771 -272.035103)
		(end 95.571056 -272.19275)
		(width 0.088646)
		(layer "In6.Cu")
		(net "M_C_CPU1_SA_DQ<8>")
	)
	(segment
		(start 31.972758 -308.2417)
		(end 32.51708 -308.2417)
		(width 0.20066)
		(layer "F.Cu")
		(net "M_C_CPU1_SA_DQ<7>")
	)
	(segment
		(start 32.794702 -307.81244)
		(end 33.189926 -307.81244)
		(width 0.20066)
		(layer "F.Cu")
		(net "M_C_CPU1_SA_DQ<7>")
	)
	(segment
		(start 34.055812 -307.816758)
		(end 34.871914 -307.816758)
		(width 0.20066)
		(layer "F.Cu")
		(net "M_C_CPU1_SA_DQ<7>")
	)
	(segment
		(start 32.51708 -308.2417)
		(end 32.666178 -308.092602)
		(width 0.20066)
		(layer "F.Cu")
		(net "M_C_CPU1_SA_DQ<7>")
	)
	(segment
		(start 29.025342 -307.816758)
		(end 29.151326 -307.942742)
		(width 0.20066)
		(layer "F.Cu")
		(net "M_C_CPU1_SA_DQ<7>")
	)
	(segment
		(start 29.151326 -308.11343)
		(end 29.29382 -308.255924)
		(width 0.20066)
		(layer "F.Cu")
		(net "M_C_CPU1_SA_DQ<7>")
	)
	(segment
		(start 32.666178 -308.092602)
		(end 32.666178 -307.940964)
		(width 0.20066)
		(layer "F.Cu")
		(net "M_C_CPU1_SA_DQ<7>")
	)
	(segment
		(start 29.899864 -308.2417)
		(end 31.972758 -308.2417)
		(width 0.1016)
		(layer "F.Cu")
		(net "M_C_CPU1_SA_DQ<7>")
	)
	(segment
		(start 29.647642 -308.255924)
		(end 29.661866 -308.2417)
		(width 0.101854)
		(layer "F.Cu")
		(net "M_C_CPU1_SA_DQ<7>")
	)
	(segment
		(start 33.189926 -307.81244)
		(end 33.401762 -308.024276)
		(width 0.20066)
		(layer "F.Cu")
		(net "M_C_CPU1_SA_DQ<7>")
	)
	(segment
		(start 29.151326 -307.942742)
		(end 29.151326 -308.11343)
		(width 0.20066)
		(layer "F.Cu")
		(net "M_C_CPU1_SA_DQ<7>")
	)
	(segment
		(start 32.666178 -307.940964)
		(end 32.794702 -307.81244)
		(width 0.20066)
		(layer "F.Cu")
		(net "M_C_CPU1_SA_DQ<7>")
	)
	(segment
		(start 29.29382 -308.255924)
		(end 29.647642 -308.255924)
		(width 0.20066)
		(layer "F.Cu")
		(net "M_C_CPU1_SA_DQ<7>")
	)
	(segment
		(start 29.661866 -308.2417)
		(end 29.899864 -308.2417)
		(width 0.101854)
		(layer "F.Cu")
		(net "M_C_CPU1_SA_DQ<7>")
	)
	(segment
		(start 27.328114 -307.816758)
		(end 29.025342 -307.816758)
		(width 0.20066)
		(layer "F.Cu")
		(net "M_C_CPU1_SA_DQ<7>")
	)
	(segment
		(start 33.848294 -308.024276)
		(end 34.055812 -307.816758)
		(width 0.20066)
		(layer "F.Cu")
		(net "M_C_CPU1_SA_DQ<7>")
	)
	(segment
		(start 33.401762 -308.024276)
		(end 33.848294 -308.024276)
		(width 0.20066)
		(layer "F.Cu")
		(net "M_C_CPU1_SA_DQ<7>")
	)
	(segment
		(start 35.976814 -307.816758)
		(end 34.871914 -307.816758)
		(width 0.20066)
		(layer "F.Cu")
		(net "M_C_CPU1_SA_DQ<7>")
	)
	(arc
		(start 93.424248 -275.35886)
		(mid 93.424184 -275.62683)
		(end 93.423994 -275.8948)
		(width 0.20066)
		(layer "F.Cu")
		(net "M_C_CPU1_SA_DQ<7>")
	)
	(segment
		(start 40.364156 -307.179472)
		(end 40.364156 -306.723542)
		(width 0.18288)
		(layer "In4.Cu")
		(net "M_C_CPU1_SA_DQ<7>")
	)
	(segment
		(start 93.111066 -275.8948)
		(end 93.046042 -275.829776)
		(width 0.088646)
		(layer "In4.Cu")
		(net "M_C_CPU1_SA_DQ<7>")
	)
	(segment
		(start 45.395134 -308.395116)
		(end 45.395134 -308.931564)
		(width 0.18288)
		(layer "In4.Cu")
		(net "M_C_CPU1_SA_DQ<7>")
	)
	(segment
		(start 87.981028 -277.841964)
		(end 87.972138 -277.847044)
		(width 0.088646)
		(layer "In4.Cu")
		(net "M_C_CPU1_SA_DQ<7>")
	)
	(segment
		(start 39.147496 -307.298852)
		(end 38.982396 -307.133752)
		(width 0.18288)
		(layer "In4.Cu")
		(net "M_C_CPU1_SA_DQ<7>")
	)
	(segment
		(start 42.878502 -307.559456)
		(end 42.718482 -307.399436)
		(width 0.18288)
		(layer "In4.Cu")
		(net "M_C_CPU1_SA_DQ<7>")
	)
	(segment
		(start 38.291516 -307.147214)
		(end 38.131496 -307.307234)
		(width 0.18288)
		(layer "In4.Cu")
		(net "M_C_CPU1_SA_DQ<7>")
	)
	(segment
		(start 93.423994 -275.8948)
		(end 93.111066 -275.8948)
		(width 0.088646)
		(layer "In4.Cu")
		(net "M_C_CPU1_SA_DQ<7>")
	)
	(segment
		(start 46.086014 -308.931564)
		(end 46.086014 -308.417976)
		(width 0.18288)
		(layer "In4.Cu")
		(net "M_C_CPU1_SA_DQ<7>")
	)
	(segment
		(start 87.689944 -278.321008)
		(end 87.689944 -278.336502)
		(width 0.088646)
		(layer "In4.Cu")
		(net "M_C_CPU1_SA_DQ<7>")
	)
	(segment
		(start 64.346328 -305.69154)
		(end 62.647576 -307.390292)
		(width 0.18288)
		(layer "In4.Cu")
		(net "M_C_CPU1_SA_DQ<7>")
	)
	(segment
		(start 39.673276 -306.700682)
		(end 39.673276 -307.121052)
		(width 0.18288)
		(layer "In4.Cu")
		(net "M_C_CPU1_SA_DQ<7>")
	)
	(segment
		(start 86.280244 -280.759662)
		(end 86.280244 -280.778204)
		(width 0.088646)
		(layer "In4.Cu")
		(net "M_C_CPU1_SA_DQ<7>")
	)
	(segment
		(start 44.275248 -307.695092)
		(end 44.139612 -307.559456)
		(width 0.18288)
		(layer "In4.Cu")
		(net "M_C_CPU1_SA_DQ<7>")
	)
	(segment
		(start 37.435536 -306.571142)
		(end 37.092636 -306.571142)
		(width 0.18288)
		(layer "In4.Cu")
		(net "M_C_CPU1_SA_DQ<7>")
	)
	(segment
		(start 79.430118 -286.817562)
		(end 75.769216 -295.655492)
		(width 0.18288)
		(layer "In4.Cu")
		(net "M_C_CPU1_SA_DQ<7>")
	)
	(segment
		(start 46.246034 -309.091584)
		(end 46.086014 -308.931564)
		(width 0.18288)
		(layer "In4.Cu")
		(net "M_C_CPU1_SA_DQ<7>")
	)
	(segment
		(start 56.9087 -308.2417)
		(end 50.886868 -308.2417)
		(width 0.18288)
		(layer "In4.Cu")
		(net "M_C_CPU1_SA_DQ<7>")
	)
	(segment
		(start 91.27236 -275.398992)
		(end 91.261946 -275.405088)
		(width 0.088646)
		(layer "In4.Cu")
		(net "M_C_CPU1_SA_DQ<7>")
	)
	(segment
		(start 88.451182 -277.027894)
		(end 88.442292 -277.032974)
		(width 0.088646)
		(layer "In4.Cu")
		(net "M_C_CPU1_SA_DQ<7>")
	)
	(segment
		(start 66.464434 -305.69154)
		(end 64.346328 -305.69154)
		(width 0.18288)
		(layer "In4.Cu")
		(net "M_C_CPU1_SA_DQ<7>")
	)
	(segment
		(start 88.629744 -276.69871)
		(end 88.629744 -276.708616)
		(width 0.088646)
		(layer "In4.Cu")
		(net "M_C_CPU1_SA_DQ<7>")
	)
	(segment
		(start 42.718482 -307.399436)
		(end 42.718482 -306.02936)
		(width 0.18288)
		(layer "In4.Cu")
		(net "M_C_CPU1_SA_DQ<7>")
	)
	(segment
		(start 45.235114 -309.091584)
		(end 44.926758 -309.091584)
		(width 0.18288)
		(layer "In4.Cu")
		(net "M_C_CPU1_SA_DQ<7>")
	)
	(segment
		(start 50.036984 -309.091584)
		(end 46.246034 -309.091584)
		(width 0.18288)
		(layer "In4.Cu")
		(net "M_C_CPU1_SA_DQ<7>")
	)
	(segment
		(start 42.210482 -305.86934)
		(end 42.027602 -306.05222)
		(width 0.18288)
		(layer "In4.Cu")
		(net "M_C_CPU1_SA_DQ<7>")
	)
	(segment
		(start 68.424044 -303.000664)
		(end 68.424044 -303.73193)
		(width 0.18288)
		(layer "In4.Cu")
		(net "M_C_CPU1_SA_DQ<7>")
	)
	(segment
		(start 85.975698 -281.192224)
		(end 85.959188 -281.208734)
		(width 0.088646)
		(layer "In4.Cu")
		(net "M_C_CPU1_SA_DQ<7>")
	)
	(segment
		(start 44.139612 -307.559456)
		(end 42.878502 -307.559456)
		(width 0.18288)
		(layer "In4.Cu")
		(net "M_C_CPU1_SA_DQ<7>")
	)
	(segment
		(start 86.101682 -281.097482)
		(end 86.092792 -281.102562)
		(width 0.088646)
		(layer "In4.Cu")
		(net "M_C_CPU1_SA_DQ<7>")
	)
	(segment
		(start 45.555154 -308.235096)
		(end 45.395134 -308.395116)
		(width 0.18288)
		(layer "In4.Cu")
		(net "M_C_CPU1_SA_DQ<7>")
	)
	(segment
		(start 87.220298 -279.134824)
		(end 87.220298 -279.150318)
		(width 0.088646)
		(layer "In4.Cu")
		(net "M_C_CPU1_SA_DQ<7>")
	)
	(segment
		(start 40.181276 -306.540662)
		(end 39.833296 -306.540662)
		(width 0.18288)
		(layer "In4.Cu")
		(net "M_C_CPU1_SA_DQ<7>")
	)
	(segment
		(start 86.571582 -280.283412)
		(end 86.562692 -280.288492)
		(width 0.088646)
		(layer "In4.Cu")
		(net "M_C_CPU1_SA_DQ<7>")
	)
	(segment
		(start 42.558462 -305.86934)
		(end 42.210482 -305.86934)
		(width 0.18288)
		(layer "In4.Cu")
		(net "M_C_CPU1_SA_DQ<7>")
	)
	(segment
		(start 85.249258 -281.208734)
		(end 85.038946 -281.208734)
		(width 0.18288)
		(layer "In4.Cu")
		(net "M_C_CPU1_SA_DQ<7>")
	)
	(segment
		(start 87.032846 -279.474676)
		(end 87.02675 -279.478232)
		(width 0.088646)
		(layer "In4.Cu")
		(net "M_C_CPU1_SA_DQ<7>")
	)
	(segment
		(start 85.038946 -281.208734)
		(end 79.430118 -286.817562)
		(width 0.18288)
		(layer "In4.Cu")
		(net "M_C_CPU1_SA_DQ<7>")
	)
	(segment
		(start 37.092636 -306.571142)
		(end 36.909756 -306.754022)
		(width 0.18288)
		(layer "In4.Cu")
		(net "M_C_CPU1_SA_DQ<7>")
	)
	(segment
		(start 87.511382 -278.65578)
		(end 87.502492 -278.66086)
		(width 0.088646)
		(layer "In4.Cu")
		(net "M_C_CPU1_SA_DQ<7>")
	)
	(segment
		(start 88.15959 -277.522432)
		(end 88.15959 -277.522686)
		(width 0.088646)
		(layer "In4.Cu")
		(net "M_C_CPU1_SA_DQ<7>")
	)
	(segment
		(start 38.822376 -305.87442)
		(end 38.474396 -305.87442)
		(width 0.18288)
		(layer "In4.Cu")
		(net "M_C_CPU1_SA_DQ<7>")
	)
	(segment
		(start 68.424044 -303.73193)
		(end 66.464434 -305.69154)
		(width 0.18288)
		(layer "In4.Cu")
		(net "M_C_CPU1_SA_DQ<7>")
	)
	(segment
		(start 37.600636 -306.736242)
		(end 37.435536 -306.571142)
		(width 0.18288)
		(layer "In4.Cu")
		(net "M_C_CPU1_SA_DQ<7>")
	)
	(segment
		(start 40.364156 -306.723542)
		(end 40.181276 -306.540662)
		(width 0.18288)
		(layer "In4.Cu")
		(net "M_C_CPU1_SA_DQ<7>")
	)
	(segment
		(start 39.833296 -306.540662)
		(end 39.673276 -306.700682)
		(width 0.18288)
		(layer "In4.Cu")
		(net "M_C_CPU1_SA_DQ<7>")
	)
	(segment
		(start 38.982396 -307.133752)
		(end 38.982396 -306.03444)
		(width 0.18288)
		(layer "In4.Cu")
		(net "M_C_CPU1_SA_DQ<7>")
	)
	(segment
		(start 38.291516 -306.0573)
		(end 38.291516 -307.147214)
		(width 0.18288)
		(layer "In4.Cu")
		(net "M_C_CPU1_SA_DQ<7>")
	)
	(segment
		(start 38.474396 -305.87442)
		(end 38.291516 -306.0573)
		(width 0.18288)
		(layer "In4.Cu")
		(net "M_C_CPU1_SA_DQ<7>")
	)
	(segment
		(start 44.275248 -308.440074)
		(end 44.275248 -307.695092)
		(width 0.18288)
		(layer "In4.Cu")
		(net "M_C_CPU1_SA_DQ<7>")
	)
	(segment
		(start 62.647576 -307.390292)
		(end 57.760108 -307.390292)
		(width 0.18288)
		(layer "In4.Cu")
		(net "M_C_CPU1_SA_DQ<7>")
	)
	(segment
		(start 88.159844 -277.508208)
		(end 88.15959 -277.522432)
		(width 0.088646)
		(layer "In4.Cu")
		(net "M_C_CPU1_SA_DQ<7>")
	)
	(segment
		(start 42.027602 -306.05222)
		(end 42.027602 -307.363876)
		(width 0.18288)
		(layer "In4.Cu")
		(net "M_C_CPU1_SA_DQ<7>")
	)
	(segment
		(start 46.086014 -308.417976)
		(end 45.903134 -308.235096)
		(width 0.18288)
		(layer "In4.Cu")
		(net "M_C_CPU1_SA_DQ<7>")
	)
	(segment
		(start 39.673276 -307.121052)
		(end 39.495476 -307.298852)
		(width 0.18288)
		(layer "In4.Cu")
		(net "M_C_CPU1_SA_DQ<7>")
	)
	(segment
		(start 42.718482 -306.02936)
		(end 42.558462 -305.86934)
		(width 0.18288)
		(layer "In4.Cu")
		(net "M_C_CPU1_SA_DQ<7>")
	)
	(segment
		(start 75.769216 -295.655492)
		(end 68.424044 -303.000664)
		(width 0.18288)
		(layer "In4.Cu")
		(net "M_C_CPU1_SA_DQ<7>")
	)
	(segment
		(start 87.041736 -279.469596)
		(end 87.032846 -279.474676)
		(width 0.088646)
		(layer "In4.Cu")
		(net "M_C_CPU1_SA_DQ<7>")
	)
	(segment
		(start 45.395134 -308.931564)
		(end 45.235114 -309.091584)
		(width 0.18288)
		(layer "In4.Cu")
		(net "M_C_CPU1_SA_DQ<7>")
	)
	(segment
		(start 90.332306 -275.398992)
		(end 90.321892 -275.405088)
		(width 0.088646)
		(layer "In4.Cu")
		(net "M_C_CPU1_SA_DQ<7>")
	)
	(segment
		(start 38.982396 -306.03444)
		(end 38.822376 -305.87442)
		(width 0.18288)
		(layer "In4.Cu")
		(net "M_C_CPU1_SA_DQ<7>")
	)
	(segment
		(start 36.909756 -306.754022)
		(end 36.909756 -306.883816)
		(width 0.18288)
		(layer "In4.Cu")
		(net "M_C_CPU1_SA_DQ<7>")
	)
	(segment
		(start 40.74414 -307.559456)
		(end 40.364156 -307.179472)
		(width 0.18288)
		(layer "In4.Cu")
		(net "M_C_CPU1_SA_DQ<7>")
	)
	(segment
		(start 85.959188 -281.208734)
		(end 85.249258 -281.208734)
		(width 0.088646)
		(layer "In4.Cu")
		(net "M_C_CPU1_SA_DQ<7>")
	)
	(segment
		(start 42.027602 -307.363876)
		(end 41.832022 -307.559456)
		(width 0.18288)
		(layer "In4.Cu")
		(net "M_C_CPU1_SA_DQ<7>")
	)
	(segment
		(start 37.788596 -307.307234)
		(end 37.600636 -307.119274)
		(width 0.18288)
		(layer "In4.Cu")
		(net "M_C_CPU1_SA_DQ<7>")
	)
	(segment
		(start 38.131496 -307.307234)
		(end 37.788596 -307.307234)
		(width 0.18288)
		(layer "In4.Cu")
		(net "M_C_CPU1_SA_DQ<7>")
	)
	(segment
		(start 57.760108 -307.390292)
		(end 56.9087 -308.2417)
		(width 0.18288)
		(layer "In4.Cu")
		(net "M_C_CPU1_SA_DQ<7>")
	)
	(segment
		(start 45.903134 -308.235096)
		(end 45.555154 -308.235096)
		(width 0.18288)
		(layer "In4.Cu")
		(net "M_C_CPU1_SA_DQ<7>")
	)
	(segment
		(start 41.832022 -307.559456)
		(end 40.74414 -307.559456)
		(width 0.18288)
		(layer "In4.Cu")
		(net "M_C_CPU1_SA_DQ<7>")
	)
	(segment
		(start 92.211906 -275.398992)
		(end 92.201492 -275.405088)
		(width 0.088646)
		(layer "In4.Cu")
		(net "M_C_CPU1_SA_DQ<7>")
	)
	(segment
		(start 89.099644 -275.876258)
		(end 89.099644 -275.8948)
		(width 0.088646)
		(layer "In4.Cu")
		(net "M_C_CPU1_SA_DQ<7>")
	)
	(segment
		(start 36.909756 -306.883816)
		(end 35.976814 -307.816758)
		(width 0.18288)
		(layer "In4.Cu")
		(net "M_C_CPU1_SA_DQ<7>")
	)
	(segment
		(start 44.926758 -309.091584)
		(end 44.275248 -308.440074)
		(width 0.18288)
		(layer "In4.Cu")
		(net "M_C_CPU1_SA_DQ<7>")
	)
	(segment
		(start 37.600636 -307.119274)
		(end 37.600636 -306.736242)
		(width 0.18288)
		(layer "In4.Cu")
		(net "M_C_CPU1_SA_DQ<7>")
	)
	(segment
		(start 88.921082 -276.214078)
		(end 88.912192 -276.219158)
		(width 0.088646)
		(layer "In4.Cu")
		(net "M_C_CPU1_SA_DQ<7>")
	)
	(segment
		(start 50.886868 -308.2417)
		(end 50.036984 -309.091584)
		(width 0.18288)
		(layer "In4.Cu")
		(net "M_C_CPU1_SA_DQ<7>")
	)
	(segment
		(start 39.495476 -307.298852)
		(end 39.147496 -307.298852)
		(width 0.18288)
		(layer "In4.Cu")
		(net "M_C_CPU1_SA_DQ<7>")
	)
	(arc
		(start 89.947496 -275.405088)
		(mid 89.664794 -275.329346)
		(end 89.382092 -275.405088)
		(width 0.088646)
		(layer "In4.Cu")
		(net "M_C_CPU1_SA_DQ<7>")
	)
	(arc
		(start 86.280244 -280.778204)
		(mid 86.232565 -280.961104)
		(end 86.101682 -281.097482)
		(width 0.088646)
		(layer "In4.Cu")
		(net "M_C_CPU1_SA_DQ<7>")
	)
	(arc
		(start 91.827096 -275.405088)
		(mid 91.550537 -275.329379)
		(end 91.27236 -275.398992)
		(width 0.088646)
		(layer "In4.Cu")
		(net "M_C_CPU1_SA_DQ<7>")
	)
	(arc
		(start 93.046042 -275.829776)
		(mid 92.956973 -275.584347)
		(end 92.76715 -275.405088)
		(width 0.088646)
		(layer "In4.Cu")
		(net "M_C_CPU1_SA_DQ<7>")
	)
	(arc
		(start 89.099644 -275.8948)
		(mid 89.051965 -276.0777)
		(end 88.921082 -276.214078)
		(width 0.088646)
		(layer "In4.Cu")
		(net "M_C_CPU1_SA_DQ<7>")
	)
	(arc
		(start 88.15959 -277.522686)
		(mid 88.111911 -277.705586)
		(end 87.981028 -277.841964)
		(width 0.088646)
		(layer "In4.Cu")
		(net "M_C_CPU1_SA_DQ<7>")
	)
	(arc
		(start 87.02675 -279.478232)
		(mid 86.824163 -279.684583)
		(end 86.750144 -279.964134)
		(width 0.088646)
		(layer "In4.Cu")
		(net "M_C_CPU1_SA_DQ<7>")
	)
	(arc
		(start 91.261946 -275.405088)
		(mid 91.074748 -275.455231)
		(end 90.88755 -275.405088)
		(width 0.088646)
		(layer "In4.Cu")
		(net "M_C_CPU1_SA_DQ<7>")
	)
	(arc
		(start 92.76715 -275.405088)
		(mid 92.490337 -275.329252)
		(end 92.211906 -275.398992)
		(width 0.088646)
		(layer "In4.Cu")
		(net "M_C_CPU1_SA_DQ<7>")
	)
	(arc
		(start 88.442292 -277.032974)
		(mid 88.239056 -277.233721)
		(end 88.159844 -277.508208)
		(width 0.088646)
		(layer "In4.Cu")
		(net "M_C_CPU1_SA_DQ<7>")
	)
	(arc
		(start 90.321892 -275.405088)
		(mid 90.134694 -275.455231)
		(end 89.947496 -275.405088)
		(width 0.088646)
		(layer "In4.Cu")
		(net "M_C_CPU1_SA_DQ<7>")
	)
	(arc
		(start 87.220298 -279.150318)
		(mid 87.172619 -279.333218)
		(end 87.041736 -279.469596)
		(width 0.088646)
		(layer "In4.Cu")
		(net "M_C_CPU1_SA_DQ<7>")
	)
	(arc
		(start 88.912192 -276.219158)
		(mid 88.707857 -276.421763)
		(end 88.629744 -276.69871)
		(width 0.088646)
		(layer "In4.Cu")
		(net "M_C_CPU1_SA_DQ<7>")
	)
	(arc
		(start 89.382092 -275.405088)
		(mid 89.179806 -275.604069)
		(end 89.099644 -275.876258)
		(width 0.088646)
		(layer "In4.Cu")
		(net "M_C_CPU1_SA_DQ<7>")
	)
	(arc
		(start 87.972138 -277.847044)
		(mid 87.769315 -278.047275)
		(end 87.689944 -278.321008)
		(width 0.088646)
		(layer "In4.Cu")
		(net "M_C_CPU1_SA_DQ<7>")
	)
	(arc
		(start 92.201492 -275.405088)
		(mid 92.014294 -275.455231)
		(end 91.827096 -275.405088)
		(width 0.088646)
		(layer "In4.Cu")
		(net "M_C_CPU1_SA_DQ<7>")
	)
	(arc
		(start 86.003892 -281.165808)
		(mid 85.989573 -281.178779)
		(end 85.975698 -281.192224)
		(width 0.088646)
		(layer "In4.Cu")
		(net "M_C_CPU1_SA_DQ<7>")
	)
	(arc
		(start 87.689944 -278.336502)
		(mid 87.642265 -278.519402)
		(end 87.511382 -278.65578)
		(width 0.088646)
		(layer "In4.Cu")
		(net "M_C_CPU1_SA_DQ<7>")
	)
	(arc
		(start 86.092792 -281.102562)
		(mid 86.046815 -281.132038)
		(end 86.003892 -281.165808)
		(width 0.088646)
		(layer "In4.Cu")
		(net "M_C_CPU1_SA_DQ<7>")
	)
	(arc
		(start 86.562692 -280.288492)
		(mid 86.360406 -280.487473)
		(end 86.280244 -280.759662)
		(width 0.088646)
		(layer "In4.Cu")
		(net "M_C_CPU1_SA_DQ<7>")
	)
	(arc
		(start 88.629744 -276.708616)
		(mid 88.582065 -276.891516)
		(end 88.451182 -277.027894)
		(width 0.088646)
		(layer "In4.Cu")
		(net "M_C_CPU1_SA_DQ<7>")
	)
	(arc
		(start 86.750144 -279.964134)
		(mid 86.702465 -280.147034)
		(end 86.571582 -280.283412)
		(width 0.088646)
		(layer "In4.Cu")
		(net "M_C_CPU1_SA_DQ<7>")
	)
	(arc
		(start 87.502492 -278.66086)
		(mid 87.299669 -278.861091)
		(end 87.220298 -279.134824)
		(width 0.088646)
		(layer "In4.Cu")
		(net "M_C_CPU1_SA_DQ<7>")
	)
	(arc
		(start 90.88755 -275.405088)
		(mid 90.610737 -275.329252)
		(end 90.332306 -275.398992)
		(width 0.088646)
		(layer "In4.Cu")
		(net "M_C_CPU1_SA_DQ<7>")
	)
	(segment
		(start 28.91028 -309.081678)
		(end 29.647642 -309.081678)
		(width 0.20066)
		(layer "F.Cu")
		(net "M_C_CPU1_SA_DQ<6>")
	)
	(segment
		(start 29.657802 -309.091838)
		(end 29.912818 -309.091838)
		(width 0.101854)
		(layer "F.Cu")
		(net "M_C_CPU1_SA_DQ<6>")
	)
	(segment
		(start 32.74949 -309.56123)
		(end 32.916876 -309.728616)
		(width 0.20066)
		(layer "F.Cu")
		(net "M_C_CPU1_SA_DQ<6>")
	)
	(segment
		(start 31.972758 -309.091838)
		(end 32.605726 -309.091838)
		(width 0.20066)
		(layer "F.Cu")
		(net "M_C_CPU1_SA_DQ<6>")
	)
	(segment
		(start 33.55721 -309.51678)
		(end 34.871914 -309.51678)
		(width 0.20066)
		(layer "F.Cu")
		(net "M_C_CPU1_SA_DQ<6>")
	)
	(segment
		(start 29.647642 -309.081678)
		(end 29.657802 -309.091838)
		(width 0.101854)
		(layer "F.Cu")
		(net "M_C_CPU1_SA_DQ<6>")
	)
	(segment
		(start 35.976814 -309.51678)
		(end 34.871914 -309.51678)
		(width 0.20066)
		(layer "F.Cu")
		(net "M_C_CPU1_SA_DQ<6>")
	)
	(segment
		(start 93.893894 -276.172676)
		(end 93.893894 -276.708362)
		(width 0.20066)
		(layer "F.Cu")
		(net "M_C_CPU1_SA_DQ<6>")
	)
	(segment
		(start 93.893894 -276.708362)
		(end 93.894148 -276.708616)
		(width 0.20066)
		(layer "F.Cu")
		(net "M_C_CPU1_SA_DQ<6>")
	)
	(segment
		(start 32.605726 -309.091838)
		(end 32.74949 -309.235602)
		(width 0.20066)
		(layer "F.Cu")
		(net "M_C_CPU1_SA_DQ<6>")
	)
	(segment
		(start 33.345374 -309.728616)
		(end 33.55721 -309.51678)
		(width 0.20066)
		(layer "F.Cu")
		(net "M_C_CPU1_SA_DQ<6>")
	)
	(segment
		(start 29.912818 -309.091838)
		(end 31.972758 -309.091838)
		(width 0.1016)
		(layer "F.Cu")
		(net "M_C_CPU1_SA_DQ<6>")
	)
	(segment
		(start 27.328114 -309.51678)
		(end 28.475178 -309.51678)
		(width 0.20066)
		(layer "F.Cu")
		(net "M_C_CPU1_SA_DQ<6>")
	)
	(segment
		(start 32.916876 -309.728616)
		(end 33.345374 -309.728616)
		(width 0.20066)
		(layer "F.Cu")
		(net "M_C_CPU1_SA_DQ<6>")
	)
	(segment
		(start 32.74949 -309.235602)
		(end 32.74949 -309.56123)
		(width 0.20066)
		(layer "F.Cu")
		(net "M_C_CPU1_SA_DQ<6>")
	)
	(segment
		(start 28.475178 -309.51678)
		(end 28.91028 -309.081678)
		(width 0.20066)
		(layer "F.Cu")
		(net "M_C_CPU1_SA_DQ<6>")
	)
	(segment
		(start 42.25544 -309.10276)
		(end 42.07256 -308.91988)
		(width 0.18288)
		(layer "In4.Cu")
		(net "M_C_CPU1_SA_DQ<6>")
	)
	(segment
		(start 37.918644 -309.841646)
		(end 37.758624 -310.001666)
		(width 0.18288)
		(layer "In4.Cu")
		(net "M_C_CPU1_SA_DQ<6>")
	)
	(segment
		(start 86.571582 -281.911298)
		(end 86.562692 -281.916378)
		(width 0.088646)
		(layer "In4.Cu")
		(net "M_C_CPU1_SA_DQ<6>")
	)
	(segment
		(start 52.954428 -309.941468)
		(end 50.678842 -309.941468)
		(width 0.18288)
		(layer "In4.Cu")
		(net "M_C_CPU1_SA_DQ<6>")
	)
	(segment
		(start 49.498758 -311.121552)
		(end 47.733458 -311.121552)
		(width 0.18288)
		(layer "In4.Cu")
		(net "M_C_CPU1_SA_DQ<6>")
	)
	(segment
		(start 60.692792 -309.46979)
		(end 60.532772 -309.30977)
		(width 0.18288)
		(layer "In4.Cu")
		(net "M_C_CPU1_SA_DQ<6>")
	)
	(segment
		(start 59.261502 -309.178198)
		(end 57.909206 -309.178198)
		(width 0.18288)
		(layer "In4.Cu")
		(net "M_C_CPU1_SA_DQ<6>")
	)
	(segment
		(start 40.946832 -309.885334)
		(end 40.763698 -309.7022)
		(width 0.18288)
		(layer "In4.Cu")
		(net "M_C_CPU1_SA_DQ<6>")
	)
	(segment
		(start 44.251118 -310.850026)
		(end 42.994326 -310.850026)
		(width 0.18288)
		(layer "In4.Cu")
		(net "M_C_CPU1_SA_DQ<6>")
	)
	(segment
		(start 93.894148 -276.708616)
		(end 93.805756 -276.708616)
		(width 0.088646)
		(layer "In4.Cu")
		(net "M_C_CPU1_SA_DQ<6>")
	)
	(segment
		(start 45.089826 -310.591708)
		(end 44.509436 -310.591708)
		(width 0.18288)
		(layer "In4.Cu")
		(net "M_C_CPU1_SA_DQ<6>")
	)
	(segment
		(start 41.56456 -309.0799)
		(end 41.56456 -309.725314)
		(width 0.18288)
		(layer "In4.Cu")
		(net "M_C_CPU1_SA_DQ<6>")
	)
	(segment
		(start 76.716382 -296.116756)
		(end 69.419724 -303.413414)
		(width 0.18288)
		(layer "In4.Cu")
		(net "M_C_CPU1_SA_DQ<6>")
	)
	(segment
		(start 61.238638 -309.286656)
		(end 61.055504 -309.46979)
		(width 0.18288)
		(layer "In4.Cu")
		(net "M_C_CPU1_SA_DQ<6>")
	)
	(segment
		(start 38.078664 -308.91607)
		(end 37.918644 -309.07609)
		(width 0.18288)
		(layer "In4.Cu")
		(net "M_C_CPU1_SA_DQ<6>")
	)
	(segment
		(start 40.763698 -308.928008)
		(end 40.603678 -308.767988)
		(width 0.18288)
		(layer "In4.Cu")
		(net "M_C_CPU1_SA_DQ<6>")
	)
	(segment
		(start 57.145936 -309.941468)
		(end 56.392572 -309.941468)
		(width 0.18288)
		(layer "In4.Cu")
		(net "M_C_CPU1_SA_DQ<6>")
	)
	(segment
		(start 62.936374 -308.861714)
		(end 61.398658 -308.861714)
		(width 0.18288)
		(layer "In4.Cu")
		(net "M_C_CPU1_SA_DQ<6>")
	)
	(segment
		(start 89.569544 -276.69871)
		(end 89.569544 -276.708616)
		(width 0.088646)
		(layer "In4.Cu")
		(net "M_C_CPU1_SA_DQ<6>")
	)
	(segment
		(start 42.25544 -309.748174)
		(end 42.25544 -309.10276)
		(width 0.18288)
		(layer "In4.Cu")
		(net "M_C_CPU1_SA_DQ<6>")
	)
	(segment
		(start 89.390982 -277.027894)
		(end 89.382092 -277.032974)
		(width 0.088646)
		(layer "In4.Cu")
		(net "M_C_CPU1_SA_DQ<6>")
	)
	(segment
		(start 40.072818 -308.950868)
		(end 40.072818 -309.818786)
		(width 0.18288)
		(layer "In4.Cu")
		(net "M_C_CPU1_SA_DQ<6>")
	)
	(segment
		(start 40.603678 -308.767988)
		(end 40.255698 -308.767988)
		(width 0.18288)
		(layer "In4.Cu")
		(net "M_C_CPU1_SA_DQ<6>")
	)
	(segment
		(start 40.072818 -309.818786)
		(end 39.889938 -310.001666)
		(width 0.18288)
		(layer "In4.Cu")
		(net "M_C_CPU1_SA_DQ<6>")
	)
	(segment
		(start 61.398658 -308.861714)
		(end 61.238638 -309.021734)
		(width 0.18288)
		(layer "In4.Cu")
		(net "M_C_CPU1_SA_DQ<6>")
	)
	(segment
		(start 84.698332 -282.777184)
		(end 84.698332 -283.021786)
		(width 0.088646)
		(layer "In4.Cu")
		(net "M_C_CPU1_SA_DQ<6>")
	)
	(segment
		(start 45.289724 -310.791606)
		(end 45.089826 -310.591708)
		(width 0.18288)
		(layer "In4.Cu")
		(net "M_C_CPU1_SA_DQ<6>")
	)
	(segment
		(start 92.296996 -276.219158)
		(end 92.282264 -276.210522)
		(width 0.088646)
		(layer "In4.Cu")
		(net "M_C_CPU1_SA_DQ<6>")
	)
	(segment
		(start 87.597996 -281.102562)
		(end 87.583264 -281.093926)
		(width 0.088646)
		(layer "In4.Cu")
		(net "M_C_CPU1_SA_DQ<6>")
	)
	(segment
		(start 38.609524 -309.09895)
		(end 38.426644 -308.91607)
		(width 0.18288)
		(layer "In4.Cu")
		(net "M_C_CPU1_SA_DQ<6>")
	)
	(segment
		(start 53.868828 -309.941468)
		(end 53.624988 -309.697628)
		(width 0.18288)
		(layer "In4.Cu")
		(net "M_C_CPU1_SA_DQ<6>")
	)
	(segment
		(start 87.981282 -281.097482)
		(end 87.972392 -281.102562)
		(width 0.088646)
		(layer "In4.Cu")
		(net "M_C_CPU1_SA_DQ<6>")
	)
	(segment
		(start 89.099644 -277.512526)
		(end 89.099644 -277.531068)
		(width 0.088646)
		(layer "In4.Cu")
		(net "M_C_CPU1_SA_DQ<6>")
	)
	(segment
		(start 42.994326 -310.850026)
		(end 42.784776 -310.640476)
		(width 0.18288)
		(layer "In4.Cu")
		(net "M_C_CPU1_SA_DQ<6>")
	)
	(segment
		(start 39.889938 -310.001666)
		(end 38.769544 -310.001666)
		(width 0.18288)
		(layer "In4.Cu")
		(net "M_C_CPU1_SA_DQ<6>")
	)
	(segment
		(start 37.918644 -309.07609)
		(end 37.918644 -309.841646)
		(width 0.18288)
		(layer "In4.Cu")
		(net "M_C_CPU1_SA_DQ<6>")
	)
	(segment
		(start 42.784776 -310.27751)
		(end 42.25544 -309.748174)
		(width 0.18288)
		(layer "In4.Cu")
		(net "M_C_CPU1_SA_DQ<6>")
	)
	(segment
		(start 41.56456 -309.725314)
		(end 41.40454 -309.885334)
		(width 0.18288)
		(layer "In4.Cu")
		(net "M_C_CPU1_SA_DQ<6>")
	)
	(segment
		(start 87.972392 -280.453846)
		(end 87.981282 -280.458926)
		(width 0.088646)
		(layer "In4.Cu")
		(net "M_C_CPU1_SA_DQ<6>")
	)
	(segment
		(start 87.981282 -279.469596)
		(end 87.972392 -279.474676)
		(width 0.088646)
		(layer "In4.Cu")
		(net "M_C_CPU1_SA_DQ<6>")
	)
	(segment
		(start 63.626746 -308.171342)
		(end 62.936374 -308.861714)
		(width 0.18288)
		(layer "In4.Cu")
		(net "M_C_CPU1_SA_DQ<6>")
	)
	(segment
		(start 36.4617 -310.001666)
		(end 35.976814 -309.51678)
		(width 0.18288)
		(layer "In4.Cu")
		(net "M_C_CPU1_SA_DQ<6>")
	)
	(segment
		(start 38.769544 -310.001666)
		(end 38.609524 -309.841646)
		(width 0.18288)
		(layer "In4.Cu")
		(net "M_C_CPU1_SA_DQ<6>")
	)
	(segment
		(start 50.678842 -309.941468)
		(end 49.498758 -311.121552)
		(width 0.18288)
		(layer "In4.Cu")
		(net "M_C_CPU1_SA_DQ<6>")
	)
	(segment
		(start 42.07256 -308.91988)
		(end 41.72458 -308.91988)
		(width 0.18288)
		(layer "In4.Cu")
		(net "M_C_CPU1_SA_DQ<6>")
	)
	(segment
		(start 60.532772 -309.021734)
		(end 60.372752 -308.861714)
		(width 0.18288)
		(layer "In4.Cu")
		(net "M_C_CPU1_SA_DQ<6>")
	)
	(segment
		(start 60.372752 -308.861714)
		(end 59.577986 -308.861714)
		(width 0.18288)
		(layer "In4.Cu")
		(net "M_C_CPU1_SA_DQ<6>")
	)
	(segment
		(start 56.082184 -309.63108)
		(end 55.724552 -309.63108)
		(width 0.18288)
		(layer "In4.Cu")
		(net "M_C_CPU1_SA_DQ<6>")
	)
	(segment
		(start 61.238638 -309.021734)
		(end 61.238638 -309.286656)
		(width 0.18288)
		(layer "In4.Cu")
		(net "M_C_CPU1_SA_DQ<6>")
	)
	(segment
		(start 60.532772 -309.30977)
		(end 60.532772 -309.021734)
		(width 0.18288)
		(layer "In4.Cu")
		(net "M_C_CPU1_SA_DQ<6>")
	)
	(segment
		(start 53.624988 -309.697628)
		(end 53.198268 -309.697628)
		(width 0.18288)
		(layer "In4.Cu")
		(net "M_C_CPU1_SA_DQ<6>")
	)
	(segment
		(start 59.577986 -308.861714)
		(end 59.261502 -309.178198)
		(width 0.18288)
		(layer "In4.Cu")
		(net "M_C_CPU1_SA_DQ<6>")
	)
	(segment
		(start 42.784776 -310.640476)
		(end 42.784776 -310.27751)
		(width 0.18288)
		(layer "In4.Cu")
		(net "M_C_CPU1_SA_DQ<6>")
	)
	(segment
		(start 61.055504 -309.46979)
		(end 60.692792 -309.46979)
		(width 0.18288)
		(layer "In4.Cu")
		(net "M_C_CPU1_SA_DQ<6>")
	)
	(segment
		(start 47.733458 -311.121552)
		(end 47.403512 -310.791606)
		(width 0.18288)
		(layer "In4.Cu")
		(net "M_C_CPU1_SA_DQ<6>")
	)
	(segment
		(start 56.392572 -309.941468)
		(end 56.082184 -309.63108)
		(width 0.18288)
		(layer "In4.Cu")
		(net "M_C_CPU1_SA_DQ<6>")
	)
	(segment
		(start 38.426644 -308.91607)
		(end 38.078664 -308.91607)
		(width 0.18288)
		(layer "In4.Cu")
		(net "M_C_CPU1_SA_DQ<6>")
	)
	(segment
		(start 65.085976 -307.423312)
		(end 64.337946 -308.171342)
		(width 0.18288)
		(layer "In4.Cu")
		(net "M_C_CPU1_SA_DQ<6>")
	)
	(segment
		(start 41.40454 -309.885334)
		(end 40.946832 -309.885334)
		(width 0.18288)
		(layer "In4.Cu")
		(net "M_C_CPU1_SA_DQ<6>")
	)
	(segment
		(start 93.324426 -276.509226)
		(end 93.089476 -276.274276)
		(width 0.088646)
		(layer "In4.Cu")
		(net "M_C_CPU1_SA_DQ<6>")
	)
	(segment
		(start 87.032592 -281.102562)
		(end 87.026496 -281.106118)
		(width 0.088646)
		(layer "In4.Cu")
		(net "M_C_CPU1_SA_DQ<6>")
	)
	(segment
		(start 84.365084 -283.355034)
		(end 80.331818 -287.3883)
		(width 0.18288)
		(layer "In4.Cu")
		(net "M_C_CPU1_SA_DQ<6>")
	)
	(segment
		(start 69.419724 -303.413414)
		(end 69.419724 -304.327814)
		(width 0.18288)
		(layer "In4.Cu")
		(net "M_C_CPU1_SA_DQ<6>")
	)
	(segment
		(start 55.724552 -309.63108)
		(end 55.414164 -309.941468)
		(width 0.18288)
		(layer "In4.Cu")
		(net "M_C_CPU1_SA_DQ<6>")
	)
	(segment
		(start 40.255698 -308.767988)
		(end 40.072818 -308.950868)
		(width 0.18288)
		(layer "In4.Cu")
		(net "M_C_CPU1_SA_DQ<6>")
	)
	(segment
		(start 80.331818 -287.3883)
		(end 76.716382 -296.116756)
		(width 0.18288)
		(layer "In4.Cu")
		(net "M_C_CPU1_SA_DQ<6>")
	)
	(segment
		(start 40.763698 -309.7022)
		(end 40.763698 -308.928008)
		(width 0.18288)
		(layer "In4.Cu")
		(net "M_C_CPU1_SA_DQ<6>")
	)
	(segment
		(start 64.337946 -308.171342)
		(end 63.626746 -308.171342)
		(width 0.18288)
		(layer "In4.Cu")
		(net "M_C_CPU1_SA_DQ<6>")
	)
	(segment
		(start 44.509436 -310.591708)
		(end 44.251118 -310.850026)
		(width 0.18288)
		(layer "In4.Cu")
		(net "M_C_CPU1_SA_DQ<6>")
	)
	(segment
		(start 66.324226 -307.423312)
		(end 65.085976 -307.423312)
		(width 0.18288)
		(layer "In4.Cu")
		(net "M_C_CPU1_SA_DQ<6>")
	)
	(segment
		(start 87.689944 -279.954228)
		(end 87.689944 -279.982676)
		(width 0.088646)
		(layer "In4.Cu")
		(net "M_C_CPU1_SA_DQ<6>")
	)
	(segment
		(start 88.159844 -279.140412)
		(end 88.159844 -279.150318)
		(width 0.088646)
		(layer "In4.Cu")
		(net "M_C_CPU1_SA_DQ<6>")
	)
	(segment
		(start 57.909206 -309.178198)
		(end 57.145936 -309.941468)
		(width 0.18288)
		(layer "In4.Cu")
		(net "M_C_CPU1_SA_DQ<6>")
	)
	(segment
		(start 88.451182 -278.65578)
		(end 88.442292 -278.66086)
		(width 0.088646)
		(layer "In4.Cu")
		(net "M_C_CPU1_SA_DQ<6>")
	)
	(segment
		(start 38.609524 -309.841646)
		(end 38.609524 -309.09895)
		(width 0.18288)
		(layer "In4.Cu")
		(net "M_C_CPU1_SA_DQ<6>")
	)
	(segment
		(start 41.72458 -308.91988)
		(end 41.56456 -309.0799)
		(width 0.18288)
		(layer "In4.Cu")
		(net "M_C_CPU1_SA_DQ<6>")
	)
	(segment
		(start 85.905594 -281.840686)
		(end 85.63483 -281.840686)
		(width 0.088646)
		(layer "In4.Cu")
		(net "M_C_CPU1_SA_DQ<6>")
	)
	(segment
		(start 55.414164 -309.941468)
		(end 53.868828 -309.941468)
		(width 0.18288)
		(layer "In4.Cu")
		(net "M_C_CPU1_SA_DQ<6>")
	)
	(segment
		(start 85.63483 -281.840686)
		(end 84.698332 -282.777184)
		(width 0.088646)
		(layer "In4.Cu")
		(net "M_C_CPU1_SA_DQ<6>")
	)
	(segment
		(start 88.629744 -278.322278)
		(end 88.629744 -278.336502)
		(width 0.088646)
		(layer "In4.Cu")
		(net "M_C_CPU1_SA_DQ<6>")
	)
	(segment
		(start 37.758624 -310.001666)
		(end 36.4617 -310.001666)
		(width 0.18288)
		(layer "In4.Cu")
		(net "M_C_CPU1_SA_DQ<6>")
	)
	(segment
		(start 84.698332 -283.021786)
		(end 84.365084 -283.355034)
		(width 0.088646)
		(layer "In4.Cu")
		(net "M_C_CPU1_SA_DQ<6>")
	)
	(segment
		(start 69.419724 -304.327814)
		(end 66.324226 -307.423312)
		(width 0.18288)
		(layer "In4.Cu")
		(net "M_C_CPU1_SA_DQ<6>")
	)
	(segment
		(start 47.403512 -310.791606)
		(end 45.289724 -310.791606)
		(width 0.18288)
		(layer "In4.Cu")
		(net "M_C_CPU1_SA_DQ<6>")
	)
	(segment
		(start 53.198268 -309.697628)
		(end 52.954428 -309.941468)
		(width 0.18288)
		(layer "In4.Cu")
		(net "M_C_CPU1_SA_DQ<6>")
	)
	(arc
		(start 89.569544 -276.708616)
		(mid 89.521865 -276.891516)
		(end 89.390982 -277.027894)
		(width 0.088646)
		(layer "In4.Cu")
		(net "M_C_CPU1_SA_DQ<6>")
	)
	(arc
		(start 89.851992 -276.219158)
		(mid 89.647657 -276.421763)
		(end 89.569544 -276.69871)
		(width 0.088646)
		(layer "In4.Cu")
		(net "M_C_CPU1_SA_DQ<6>")
	)
	(arc
		(start 90.791792 -276.219158)
		(mid 90.604594 -276.269301)
		(end 90.417396 -276.219158)
		(width 0.088646)
		(layer "In4.Cu")
		(net "M_C_CPU1_SA_DQ<6>")
	)
	(arc
		(start 92.671392 -276.219158)
		(mid 92.484194 -276.269301)
		(end 92.296996 -276.219158)
		(width 0.088646)
		(layer "In4.Cu")
		(net "M_C_CPU1_SA_DQ<6>")
	)
	(arc
		(start 87.689944 -279.982676)
		(mid 87.770106 -280.254865)
		(end 87.972392 -280.453846)
		(width 0.088646)
		(layer "In4.Cu")
		(net "M_C_CPU1_SA_DQ<6>")
	)
	(arc
		(start 90.417396 -276.219158)
		(mid 90.134694 -276.143382)
		(end 89.851992 -276.219158)
		(width 0.088646)
		(layer "In4.Cu")
		(net "M_C_CPU1_SA_DQ<6>")
	)
	(arc
		(start 88.912446 -277.84679)
		(mid 88.708965 -278.047594)
		(end 88.629744 -278.322278)
		(width 0.088646)
		(layer "In4.Cu")
		(net "M_C_CPU1_SA_DQ<6>")
	)
	(arc
		(start 86.188296 -281.916378)
		(mid 86.051927 -281.859936)
		(end 85.905594 -281.840686)
		(width 0.088646)
		(layer "In4.Cu")
		(net "M_C_CPU1_SA_DQ<6>")
	)
	(arc
		(start 86.750144 -281.59202)
		(mid 86.702465 -281.77492)
		(end 86.571582 -281.911298)
		(width 0.088646)
		(layer "In4.Cu")
		(net "M_C_CPU1_SA_DQ<6>")
	)
	(arc
		(start 87.972392 -279.474676)
		(mid 87.768057 -279.677281)
		(end 87.689944 -279.954228)
		(width 0.088646)
		(layer "In4.Cu")
		(net "M_C_CPU1_SA_DQ<6>")
	)
	(arc
		(start 87.026496 -281.106118)
		(mid 86.824083 -281.312531)
		(end 86.750144 -281.59202)
		(width 0.088646)
		(layer "In4.Cu")
		(net "M_C_CPU1_SA_DQ<6>")
	)
	(arc
		(start 89.099644 -277.531068)
		(mid 89.047374 -277.713433)
		(end 88.912446 -277.84679)
		(width 0.088646)
		(layer "In4.Cu")
		(net "M_C_CPU1_SA_DQ<6>")
	)
	(arc
		(start 92.282264 -276.210522)
		(mid 92.005789 -276.143202)
		(end 91.731592 -276.219158)
		(width 0.088646)
		(layer "In4.Cu")
		(net "M_C_CPU1_SA_DQ<6>")
	)
	(arc
		(start 86.562692 -281.916378)
		(mid 86.375494 -281.966521)
		(end 86.188296 -281.916378)
		(width 0.088646)
		(layer "In4.Cu")
		(net "M_C_CPU1_SA_DQ<6>")
	)
	(arc
		(start 87.981282 -280.458926)
		(mid 88.159879 -280.778204)
		(end 87.981282 -281.097482)
		(width 0.088646)
		(layer "In4.Cu")
		(net "M_C_CPU1_SA_DQ<6>")
	)
	(arc
		(start 93.089476 -276.274276)
		(mid 92.889802 -276.175814)
		(end 92.671392 -276.219158)
		(width 0.088646)
		(layer "In4.Cu")
		(net "M_C_CPU1_SA_DQ<6>")
	)
	(arc
		(start 88.159844 -279.150318)
		(mid 88.112165 -279.333218)
		(end 87.981282 -279.469596)
		(width 0.088646)
		(layer "In4.Cu")
		(net "M_C_CPU1_SA_DQ<6>")
	)
	(arc
		(start 87.583264 -281.093926)
		(mid 87.306789 -281.026606)
		(end 87.032592 -281.102562)
		(width 0.088646)
		(layer "In4.Cu")
		(net "M_C_CPU1_SA_DQ<6>")
	)
	(arc
		(start 88.629744 -278.336502)
		(mid 88.582065 -278.519402)
		(end 88.451182 -278.65578)
		(width 0.088646)
		(layer "In4.Cu")
		(net "M_C_CPU1_SA_DQ<6>")
	)
	(arc
		(start 88.442292 -278.66086)
		(mid 88.237957 -278.863465)
		(end 88.159844 -279.140412)
		(width 0.088646)
		(layer "In4.Cu")
		(net "M_C_CPU1_SA_DQ<6>")
	)
	(arc
		(start 93.805756 -276.708616)
		(mid 93.545256 -276.656799)
		(end 93.324426 -276.509226)
		(width 0.088646)
		(layer "In4.Cu")
		(net "M_C_CPU1_SA_DQ<6>")
	)
	(arc
		(start 91.731592 -276.219158)
		(mid 91.544394 -276.269301)
		(end 91.357196 -276.219158)
		(width 0.088646)
		(layer "In4.Cu")
		(net "M_C_CPU1_SA_DQ<6>")
	)
	(arc
		(start 87.972392 -281.102562)
		(mid 87.785194 -281.152705)
		(end 87.597996 -281.102562)
		(width 0.088646)
		(layer "In4.Cu")
		(net "M_C_CPU1_SA_DQ<6>")
	)
	(arc
		(start 91.357196 -276.219158)
		(mid 91.074494 -276.143382)
		(end 90.791792 -276.219158)
		(width 0.088646)
		(layer "In4.Cu")
		(net "M_C_CPU1_SA_DQ<6>")
	)
	(arc
		(start 89.382092 -277.032974)
		(mid 89.177757 -277.235579)
		(end 89.099644 -277.512526)
		(width 0.088646)
		(layer "In4.Cu")
		(net "M_C_CPU1_SA_DQ<6>")
	)
	(segment
		(start 31.876746 -308.666642)
		(end 30.771846 -308.666642)
		(width 0.20066)
		(layer "F.Cu")
		(net "M_C_CPU1_SA_DQ<5>")
	)
	(segment
		(start 24.773636 -308.87797)
		(end 25.27808 -308.87797)
		(width 0.20066)
		(layer "F.Cu")
		(net "M_C_CPU1_SA_DQ<5>")
	)
	(segment
		(start 26.2128 -308.2417)
		(end 28.198318 -308.2417)
		(width 0.1016)
		(layer "F.Cu")
		(net "M_C_CPU1_SA_DQ<5>")
	)
	(segment
		(start 29.13253 -308.666642)
		(end 30.771846 -308.666642)
		(width 0.20066)
		(layer "F.Cu")
		(net "M_C_CPU1_SA_DQ<5>")
	)
	(segment
		(start 24.562308 -308.666642)
		(end 24.773636 -308.87797)
		(width 0.20066)
		(layer "F.Cu")
		(net "M_C_CPU1_SA_DQ<5>")
	)
	(segment
		(start 28.707588 -308.2417)
		(end 29.13253 -308.666642)
		(width 0.20066)
		(layer "F.Cu")
		(net "M_C_CPU1_SA_DQ<5>")
	)
	(segment
		(start 23.228046 -308.666642)
		(end 24.562308 -308.666642)
		(width 0.20066)
		(layer "F.Cu")
		(net "M_C_CPU1_SA_DQ<5>")
	)
	(segment
		(start 28.198318 -308.2417)
		(end 28.529026 -308.2417)
		(width 0.101854)
		(layer "F.Cu")
		(net "M_C_CPU1_SA_DQ<5>")
	)
	(segment
		(start 25.27808 -308.87797)
		(end 25.432512 -308.723538)
		(width 0.20066)
		(layer "F.Cu")
		(net "M_C_CPU1_SA_DQ<5>")
	)
	(segment
		(start 26.20391 -308.23281)
		(end 26.2128 -308.2417)
		(width 0.1016)
		(layer "F.Cu")
		(net "M_C_CPU1_SA_DQ<5>")
	)
	(segment
		(start 28.529026 -308.2417)
		(end 28.707588 -308.2417)
		(width 0.20066)
		(layer "F.Cu")
		(net "M_C_CPU1_SA_DQ<5>")
	)
	(segment
		(start 25.595072 -308.23281)
		(end 26.20391 -308.23281)
		(width 0.20066)
		(layer "F.Cu")
		(net "M_C_CPU1_SA_DQ<5>")
	)
	(segment
		(start 25.432512 -308.39537)
		(end 25.595072 -308.23281)
		(width 0.20066)
		(layer "F.Cu")
		(net "M_C_CPU1_SA_DQ<5>")
	)
	(segment
		(start 25.432512 -308.723538)
		(end 25.432512 -308.39537)
		(width 0.20066)
		(layer "F.Cu")
		(net "M_C_CPU1_SA_DQ<5>")
	)
	(arc
		(start 92.484448 -275.35886)
		(mid 92.484384 -275.62683)
		(end 92.484194 -275.8948)
		(width 0.20066)
		(layer "F.Cu")
		(net "M_C_CPU1_SA_DQ<5>")
	)
	(segment
		(start 38.461696 -307.82768)
		(end 38.113462 -307.82768)
		(width 0.18288)
		(layer "In4.Cu")
		(net "M_C_CPU1_SA_DQ<5>")
	)
	(segment
		(start 49.218342 -309.941722)
		(end 48.954944 -309.678324)
		(width 0.18288)
		(layer "In4.Cu")
		(net "M_C_CPU1_SA_DQ<5>")
	)
	(segment
		(start 49.964848 -309.941722)
		(end 49.218342 -309.941722)
		(width 0.18288)
		(layer "In4.Cu")
		(net "M_C_CPU1_SA_DQ<5>")
	)
	(segment
		(start 58.07964 -308.142894)
		(end 57.13095 -309.091584)
		(width 0.18288)
		(layer "In4.Cu")
		(net "M_C_CPU1_SA_DQ<5>")
	)
	(segment
		(start 85.901784 -281.535632)
		(end 85.443822 -281.535632)
		(width 0.088646)
		(layer "In4.Cu")
		(net "M_C_CPU1_SA_DQ<5>")
	)
	(segment
		(start 36.85286 -308.519322)
		(end 36.280598 -309.091584)
		(width 0.18288)
		(layer "In4.Cu")
		(net "M_C_CPU1_SA_DQ<5>")
	)
	(segment
		(start 64.172592 -307.587142)
		(end 63.492634 -307.587142)
		(width 0.18288)
		(layer "In4.Cu")
		(net "M_C_CPU1_SA_DQ<5>")
	)
	(segment
		(start 42.987976 -308.97068)
		(end 42.987976 -308.273958)
		(width 0.18288)
		(layer "In4.Cu")
		(net "M_C_CPU1_SA_DQ<5>")
	)
	(segment
		(start 65.215262 -306.544472)
		(end 64.172592 -307.587142)
		(width 0.18288)
		(layer "In4.Cu")
		(net "M_C_CPU1_SA_DQ<5>")
	)
	(segment
		(start 43.959018 -309.941722)
		(end 42.987976 -308.97068)
		(width 0.18288)
		(layer "In4.Cu")
		(net "M_C_CPU1_SA_DQ<5>")
	)
	(segment
		(start 86.940644 -279.964134)
		(end 86.940644 -279.982676)
		(width 0.088646)
		(layer "In4.Cu")
		(net "M_C_CPU1_SA_DQ<5>")
	)
	(segment
		(start 68.921884 -303.99228)
		(end 66.369692 -306.544472)
		(width 0.18288)
		(layer "In4.Cu")
		(net "M_C_CPU1_SA_DQ<5>")
	)
	(segment
		(start 33.511744 -307.678328)
		(end 33.328864 -307.495448)
		(width 0.18288)
		(layer "In4.Cu")
		(net "M_C_CPU1_SA_DQ<5>")
	)
	(segment
		(start 86.194138 -281.264106)
		(end 86.188042 -281.267662)
		(width 0.088646)
		(layer "In4.Cu")
		(net "M_C_CPU1_SA_DQ<5>")
	)
	(segment
		(start 34.291524 -307.986684)
		(end 34.131504 -308.146704)
		(width 0.18288)
		(layer "In4.Cu")
		(net "M_C_CPU1_SA_DQ<5>")
	)
	(segment
		(start 36.280598 -309.091584)
		(end 35.634422 -309.091584)
		(width 0.18288)
		(layer "In4.Cu")
		(net "M_C_CPU1_SA_DQ<5>")
	)
	(segment
		(start 88.820244 -276.708616)
		(end 88.820244 -276.72284)
		(width 0.088646)
		(layer "In4.Cu")
		(net "M_C_CPU1_SA_DQ<5>")
	)
	(segment
		(start 32.980884 -307.495448)
		(end 32.820864 -307.655468)
		(width 0.18288)
		(layer "In4.Cu")
		(net "M_C_CPU1_SA_DQ<5>")
	)
	(segment
		(start 85.443822 -281.535632)
		(end 84.324952 -282.654502)
		(width 0.088646)
		(layer "In4.Cu")
		(net "M_C_CPU1_SA_DQ<5>")
	)
	(segment
		(start 79.84363 -287.135824)
		(end 76.201778 -295.927272)
		(width 0.18288)
		(layer "In4.Cu")
		(net "M_C_CPU1_SA_DQ<5>")
	)
	(segment
		(start 63.492634 -307.587142)
		(end 62.73165 -308.348126)
		(width 0.18288)
		(layer "In4.Cu")
		(net "M_C_CPU1_SA_DQ<5>")
	)
	(segment
		(start 32.396684 -308.146704)
		(end 31.876746 -308.666642)
		(width 0.18288)
		(layer "In4.Cu")
		(net "M_C_CPU1_SA_DQ<5>")
	)
	(segment
		(start 32.660844 -308.146704)
		(end 32.396684 -308.146704)
		(width 0.18288)
		(layer "In4.Cu")
		(net "M_C_CPU1_SA_DQ<5>")
	)
	(segment
		(start 34.799524 -307.345588)
		(end 34.451544 -307.345588)
		(width 0.18288)
		(layer "In4.Cu")
		(net "M_C_CPU1_SA_DQ<5>")
	)
	(segment
		(start 91.357196 -275.570442)
		(end 91.342464 -275.579078)
		(width 0.088646)
		(layer "In4.Cu")
		(net "M_C_CPU1_SA_DQ<5>")
	)
	(segment
		(start 37.42182 -308.519322)
		(end 36.85286 -308.519322)
		(width 0.18288)
		(layer "In4.Cu")
		(net "M_C_CPU1_SA_DQ<5>")
	)
	(segment
		(start 34.131504 -308.146704)
		(end 33.671764 -308.146704)
		(width 0.18288)
		(layer "In4.Cu")
		(net "M_C_CPU1_SA_DQ<5>")
	)
	(segment
		(start 87.59825 -278.82596)
		(end 87.58936 -278.83104)
		(width 0.088646)
		(layer "In4.Cu")
		(net "M_C_CPU1_SA_DQ<5>")
	)
	(segment
		(start 42.860722 -308.146704)
		(end 39.919148 -308.146704)
		(width 0.18288)
		(layer "In4.Cu")
		(net "M_C_CPU1_SA_DQ<5>")
	)
	(segment
		(start 88.350344 -277.529036)
		(end 88.35009 -277.53818)
		(width 0.088646)
		(layer "In4.Cu")
		(net "M_C_CPU1_SA_DQ<5>")
	)
	(segment
		(start 50.814986 -309.091584)
		(end 49.964848 -309.941722)
		(width 0.18288)
		(layer "In4.Cu")
		(net "M_C_CPU1_SA_DQ<5>")
	)
	(segment
		(start 88.067896 -278.012144)
		(end 88.059006 -278.017224)
		(width 0.088646)
		(layer "In4.Cu")
		(net "M_C_CPU1_SA_DQ<5>")
	)
	(segment
		(start 33.511744 -307.986684)
		(end 33.511744 -307.678328)
		(width 0.18288)
		(layer "In4.Cu")
		(net "M_C_CPU1_SA_DQ<5>")
	)
	(segment
		(start 84.324952 -282.654502)
		(end 79.84363 -287.135824)
		(width 0.18288)
		(layer "In4.Cu")
		(net "M_C_CPU1_SA_DQ<5>")
	)
	(segment
		(start 86.110318 -281.327098)
		(end 85.901784 -281.535632)
		(width 0.088646)
		(layer "In4.Cu")
		(net "M_C_CPU1_SA_DQ<5>")
	)
	(segment
		(start 32.820864 -307.986684)
		(end 32.660844 -308.146704)
		(width 0.18288)
		(layer "In4.Cu")
		(net "M_C_CPU1_SA_DQ<5>")
	)
	(segment
		(start 42.987976 -308.273958)
		(end 42.860722 -308.146704)
		(width 0.18288)
		(layer "In4.Cu")
		(net "M_C_CPU1_SA_DQ<5>")
	)
	(segment
		(start 38.113462 -307.82768)
		(end 37.42182 -308.519322)
		(width 0.18288)
		(layer "In4.Cu")
		(net "M_C_CPU1_SA_DQ<5>")
	)
	(segment
		(start 53.781198 -309.091584)
		(end 53.485034 -308.79542)
		(width 0.18288)
		(layer "In4.Cu")
		(net "M_C_CPU1_SA_DQ<5>")
	)
	(segment
		(start 34.291524 -307.505608)
		(end 34.291524 -307.986684)
		(width 0.18288)
		(layer "In4.Cu")
		(net "M_C_CPU1_SA_DQ<5>")
	)
	(segment
		(start 35.220148 -308.67731)
		(end 35.220148 -308.273958)
		(width 0.18288)
		(layer "In4.Cu")
		(net "M_C_CPU1_SA_DQ<5>")
	)
	(segment
		(start 57.13095 -309.091584)
		(end 53.781198 -309.091584)
		(width 0.18288)
		(layer "In4.Cu")
		(net "M_C_CPU1_SA_DQ<5>")
	)
	(segment
		(start 33.671764 -308.146704)
		(end 33.511744 -307.986684)
		(width 0.18288)
		(layer "In4.Cu")
		(net "M_C_CPU1_SA_DQ<5>")
	)
	(segment
		(start 59.200288 -308.142894)
		(end 58.07964 -308.142894)
		(width 0.18288)
		(layer "In4.Cu")
		(net "M_C_CPU1_SA_DQ<5>")
	)
	(segment
		(start 87.880444 -278.336502)
		(end 87.880444 -278.351996)
		(width 0.088646)
		(layer "In4.Cu")
		(net "M_C_CPU1_SA_DQ<5>")
	)
	(segment
		(start 38.621716 -308.359302)
		(end 38.621716 -307.9877)
		(width 0.18288)
		(layer "In4.Cu")
		(net "M_C_CPU1_SA_DQ<5>")
	)
	(segment
		(start 92.797122 -275.8948)
		(end 92.854272 -275.83765)
		(width 0.088646)
		(layer "In4.Cu")
		(net "M_C_CPU1_SA_DQ<5>")
	)
	(segment
		(start 89.290144 -275.8948)
		(end 89.290144 -275.904706)
		(width 0.088646)
		(layer "In4.Cu")
		(net "M_C_CPU1_SA_DQ<5>")
	)
	(segment
		(start 35.220148 -308.273958)
		(end 34.982404 -308.036214)
		(width 0.18288)
		(layer "In4.Cu")
		(net "M_C_CPU1_SA_DQ<5>")
	)
	(segment
		(start 89.477596 -275.570442)
		(end 89.468706 -275.575522)
		(width 0.088646)
		(layer "In4.Cu")
		(net "M_C_CPU1_SA_DQ<5>")
	)
	(segment
		(start 35.634422 -309.091584)
		(end 35.220148 -308.67731)
		(width 0.18288)
		(layer "In4.Cu")
		(net "M_C_CPU1_SA_DQ<5>")
	)
	(segment
		(start 66.369692 -306.544472)
		(end 65.215262 -306.544472)
		(width 0.18288)
		(layer "In4.Cu")
		(net "M_C_CPU1_SA_DQ<5>")
	)
	(segment
		(start 39.54653 -308.519322)
		(end 38.781736 -308.519322)
		(width 0.18288)
		(layer "In4.Cu")
		(net "M_C_CPU1_SA_DQ<5>")
	)
	(segment
		(start 86.658196 -280.453846)
		(end 86.649306 -280.458926)
		(width 0.088646)
		(layer "In4.Cu")
		(net "M_C_CPU1_SA_DQ<5>")
	)
	(segment
		(start 59.40552 -308.348126)
		(end 59.200288 -308.142894)
		(width 0.18288)
		(layer "In4.Cu")
		(net "M_C_CPU1_SA_DQ<5>")
	)
	(segment
		(start 68.921884 -303.207166)
		(end 68.921884 -303.99228)
		(width 0.18288)
		(layer "In4.Cu")
		(net "M_C_CPU1_SA_DQ<5>")
	)
	(segment
		(start 34.982404 -307.528468)
		(end 34.799524 -307.345588)
		(width 0.18288)
		(layer "In4.Cu")
		(net "M_C_CPU1_SA_DQ<5>")
	)
	(segment
		(start 88.350344 -277.51405)
		(end 88.350344 -277.529036)
		(width 0.088646)
		(layer "In4.Cu")
		(net "M_C_CPU1_SA_DQ<5>")
	)
	(segment
		(start 92.680282 -275.575522)
		(end 92.671392 -275.570442)
		(width 0.088646)
		(layer "In4.Cu")
		(net "M_C_CPU1_SA_DQ<5>")
	)
	(segment
		(start 62.73165 -308.348126)
		(end 59.40552 -308.348126)
		(width 0.18288)
		(layer "In4.Cu")
		(net "M_C_CPU1_SA_DQ<5>")
	)
	(segment
		(start 52.767738 -309.091584)
		(end 50.814986 -309.091584)
		(width 0.18288)
		(layer "In4.Cu")
		(net "M_C_CPU1_SA_DQ<5>")
	)
	(segment
		(start 76.201778 -295.927272)
		(end 68.921884 -303.207166)
		(width 0.18288)
		(layer "In4.Cu")
		(net "M_C_CPU1_SA_DQ<5>")
	)
	(segment
		(start 53.485034 -308.79542)
		(end 53.063902 -308.79542)
		(width 0.18288)
		(layer "In4.Cu")
		(net "M_C_CPU1_SA_DQ<5>")
	)
	(segment
		(start 48.330358 -309.678324)
		(end 48.06696 -309.941722)
		(width 0.18288)
		(layer "In4.Cu")
		(net "M_C_CPU1_SA_DQ<5>")
	)
	(segment
		(start 34.982404 -308.036214)
		(end 34.982404 -307.528468)
		(width 0.18288)
		(layer "In4.Cu")
		(net "M_C_CPU1_SA_DQ<5>")
	)
	(segment
		(start 48.06696 -309.941722)
		(end 43.959018 -309.941722)
		(width 0.18288)
		(layer "In4.Cu")
		(net "M_C_CPU1_SA_DQ<5>")
	)
	(segment
		(start 48.954944 -309.678324)
		(end 48.330358 -309.678324)
		(width 0.18288)
		(layer "In4.Cu")
		(net "M_C_CPU1_SA_DQ<5>")
	)
	(segment
		(start 33.328864 -307.495448)
		(end 32.980884 -307.495448)
		(width 0.18288)
		(layer "In4.Cu")
		(net "M_C_CPU1_SA_DQ<5>")
	)
	(segment
		(start 92.484194 -275.8948)
		(end 92.797122 -275.8948)
		(width 0.088646)
		(layer "In4.Cu")
		(net "M_C_CPU1_SA_DQ<5>")
	)
	(segment
		(start 87.134192 -279.63622)
		(end 87.128096 -279.639776)
		(width 0.088646)
		(layer "In4.Cu")
		(net "M_C_CPU1_SA_DQ<5>")
	)
	(segment
		(start 89.007696 -276.384258)
		(end 88.998806 -276.389338)
		(width 0.088646)
		(layer "In4.Cu")
		(net "M_C_CPU1_SA_DQ<5>")
	)
	(segment
		(start 53.063902 -308.79542)
		(end 52.767738 -309.091584)
		(width 0.18288)
		(layer "In4.Cu")
		(net "M_C_CPU1_SA_DQ<5>")
	)
	(segment
		(start 39.919148 -308.146704)
		(end 39.54653 -308.519322)
		(width 0.18288)
		(layer "In4.Cu")
		(net "M_C_CPU1_SA_DQ<5>")
	)
	(segment
		(start 38.781736 -308.519322)
		(end 38.621716 -308.359302)
		(width 0.18288)
		(layer "In4.Cu")
		(net "M_C_CPU1_SA_DQ<5>")
	)
	(segment
		(start 34.451544 -307.345588)
		(end 34.291524 -307.505608)
		(width 0.18288)
		(layer "In4.Cu")
		(net "M_C_CPU1_SA_DQ<5>")
	)
	(segment
		(start 32.820864 -307.655468)
		(end 32.820864 -307.986684)
		(width 0.18288)
		(layer "In4.Cu")
		(net "M_C_CPU1_SA_DQ<5>")
	)
	(segment
		(start 38.621716 -307.9877)
		(end 38.461696 -307.82768)
		(width 0.18288)
		(layer "In4.Cu")
		(net "M_C_CPU1_SA_DQ<5>")
	)
	(segment
		(start 87.128096 -279.639776)
		(end 87.119206 -279.644856)
		(width 0.088646)
		(layer "In4.Cu")
		(net "M_C_CPU1_SA_DQ<5>")
	)
	(arc
		(start 87.880444 -278.351996)
		(mid 87.801074 -278.62573)
		(end 87.59825 -278.82596)
		(width 0.088646)
		(layer "In4.Cu")
		(net "M_C_CPU1_SA_DQ<5>")
	)
	(arc
		(start 87.119206 -279.644856)
		(mid 86.988292 -279.781216)
		(end 86.940644 -279.964134)
		(width 0.088646)
		(layer "In4.Cu")
		(net "M_C_CPU1_SA_DQ<5>")
	)
	(arc
		(start 89.468706 -275.575522)
		(mid 89.337792 -275.711882)
		(end 89.290144 -275.8948)
		(width 0.088646)
		(layer "In4.Cu")
		(net "M_C_CPU1_SA_DQ<5>")
	)
	(arc
		(start 88.998806 -276.389338)
		(mid 88.867892 -276.525698)
		(end 88.820244 -276.708616)
		(width 0.088646)
		(layer "In4.Cu")
		(net "M_C_CPU1_SA_DQ<5>")
	)
	(arc
		(start 92.296996 -275.570442)
		(mid 92.014294 -275.646184)
		(end 91.731592 -275.570442)
		(width 0.088646)
		(layer "In4.Cu")
		(net "M_C_CPU1_SA_DQ<5>")
	)
	(arc
		(start 92.671392 -275.570442)
		(mid 92.484194 -275.520299)
		(end 92.296996 -275.570442)
		(width 0.088646)
		(layer "In4.Cu")
		(net "M_C_CPU1_SA_DQ<5>")
	)
	(arc
		(start 87.58936 -278.83104)
		(mid 87.458446 -278.9674)
		(end 87.410798 -279.150318)
		(width 0.088646)
		(layer "In4.Cu")
		(net "M_C_CPU1_SA_DQ<5>")
	)
	(arc
		(start 92.854272 -275.83765)
		(mid 92.796153 -275.687409)
		(end 92.680282 -275.575522)
		(width 0.088646)
		(layer "In4.Cu")
		(net "M_C_CPU1_SA_DQ<5>")
	)
	(arc
		(start 91.731592 -275.570442)
		(mid 91.544394 -275.520299)
		(end 91.357196 -275.570442)
		(width 0.088646)
		(layer "In4.Cu")
		(net "M_C_CPU1_SA_DQ<5>")
	)
	(arc
		(start 90.791792 -275.570442)
		(mid 90.604594 -275.520299)
		(end 90.417396 -275.570442)
		(width 0.088646)
		(layer "In4.Cu")
		(net "M_C_CPU1_SA_DQ<5>")
	)
	(arc
		(start 90.417396 -275.570442)
		(mid 90.134694 -275.646184)
		(end 89.851992 -275.570442)
		(width 0.088646)
		(layer "In4.Cu")
		(net "M_C_CPU1_SA_DQ<5>")
	)
	(arc
		(start 86.470744 -280.778204)
		(mid 86.396753 -281.05777)
		(end 86.194138 -281.264106)
		(width 0.088646)
		(layer "In4.Cu")
		(net "M_C_CPU1_SA_DQ<5>")
	)
	(arc
		(start 88.059006 -278.017224)
		(mid 87.928092 -278.153584)
		(end 87.880444 -278.336502)
		(width 0.088646)
		(layer "In4.Cu")
		(net "M_C_CPU1_SA_DQ<5>")
	)
	(arc
		(start 88.820244 -276.72284)
		(mid 88.741025 -276.997525)
		(end 88.537542 -277.198328)
		(width 0.088646)
		(layer "In4.Cu")
		(net "M_C_CPU1_SA_DQ<5>")
	)
	(arc
		(start 86.649306 -280.458926)
		(mid 86.518392 -280.595286)
		(end 86.470744 -280.778204)
		(width 0.088646)
		(layer "In4.Cu")
		(net "M_C_CPU1_SA_DQ<5>")
	)
	(arc
		(start 89.851992 -275.570442)
		(mid 89.664794 -275.520299)
		(end 89.477596 -275.570442)
		(width 0.088646)
		(layer "In4.Cu")
		(net "M_C_CPU1_SA_DQ<5>")
	)
	(arc
		(start 88.537542 -277.198328)
		(mid 88.402609 -277.331682)
		(end 88.350344 -277.51405)
		(width 0.088646)
		(layer "In4.Cu")
		(net "M_C_CPU1_SA_DQ<5>")
	)
	(arc
		(start 86.188042 -281.267662)
		(mid 86.147233 -281.294834)
		(end 86.110318 -281.327098)
		(width 0.088646)
		(layer "In4.Cu")
		(net "M_C_CPU1_SA_DQ<5>")
	)
	(arc
		(start 87.410798 -279.150318)
		(mid 87.336807 -279.429884)
		(end 87.134192 -279.63622)
		(width 0.088646)
		(layer "In4.Cu")
		(net "M_C_CPU1_SA_DQ<5>")
	)
	(arc
		(start 86.940644 -279.982676)
		(mid 86.860482 -280.254865)
		(end 86.658196 -280.453846)
		(width 0.088646)
		(layer "In4.Cu")
		(net "M_C_CPU1_SA_DQ<5>")
	)
	(arc
		(start 91.342464 -275.579078)
		(mid 91.066023 -275.646244)
		(end 90.791792 -275.570442)
		(width 0.088646)
		(layer "In4.Cu")
		(net "M_C_CPU1_SA_DQ<5>")
	)
	(arc
		(start 88.35009 -277.53818)
		(mid 88.27072 -277.811914)
		(end 88.067896 -278.012144)
		(width 0.088646)
		(layer "In4.Cu")
		(net "M_C_CPU1_SA_DQ<5>")
	)
	(arc
		(start 89.290144 -275.904706)
		(mid 89.212033 -276.181655)
		(end 89.007696 -276.384258)
		(width 0.088646)
		(layer "In4.Cu")
		(net "M_C_CPU1_SA_DQ<5>")
	)
	(segment
		(start 29.402786 -310.366664)
		(end 30.771846 -310.366664)
		(width 0.20066)
		(layer "F.Cu")
		(net "M_C_CPU1_SA_DQ<4>")
	)
	(segment
		(start 92.014294 -276.172676)
		(end 92.014294 -276.708362)
		(width 0.20066)
		(layer "F.Cu")
		(net "M_C_CPU1_SA_DQ<4>")
	)
	(segment
		(start 25.259792 -310.605424)
		(end 25.432512 -310.432704)
		(width 0.20066)
		(layer "F.Cu")
		(net "M_C_CPU1_SA_DQ<4>")
	)
	(segment
		(start 26.459942 -309.941722)
		(end 28.529026 -309.941722)
		(width 0.1016)
		(layer "F.Cu")
		(net "M_C_CPU1_SA_DQ<4>")
	)
	(segment
		(start 26.20391 -309.933594)
		(end 26.212038 -309.941722)
		(width 0.101854)
		(layer "F.Cu")
		(net "M_C_CPU1_SA_DQ<4>")
	)
	(segment
		(start 31.876746 -310.366664)
		(end 30.771846 -310.366664)
		(width 0.20066)
		(layer "F.Cu")
		(net "M_C_CPU1_SA_DQ<4>")
	)
	(segment
		(start 28.529026 -309.941722)
		(end 28.977844 -309.941722)
		(width 0.20066)
		(layer "F.Cu")
		(net "M_C_CPU1_SA_DQ<4>")
	)
	(segment
		(start 26.212038 -309.941722)
		(end 26.459942 -309.941722)
		(width 0.101854)
		(layer "F.Cu")
		(net "M_C_CPU1_SA_DQ<4>")
	)
	(segment
		(start 28.977844 -309.941722)
		(end 29.402786 -310.366664)
		(width 0.20066)
		(layer "F.Cu")
		(net "M_C_CPU1_SA_DQ<4>")
	)
	(segment
		(start 24.562308 -310.366664)
		(end 24.801068 -310.605424)
		(width 0.20066)
		(layer "F.Cu")
		(net "M_C_CPU1_SA_DQ<4>")
	)
	(segment
		(start 92.014294 -276.708362)
		(end 92.014548 -276.708616)
		(width 0.20066)
		(layer "F.Cu")
		(net "M_C_CPU1_SA_DQ<4>")
	)
	(segment
		(start 24.801068 -310.605424)
		(end 25.259792 -310.605424)
		(width 0.20066)
		(layer "F.Cu")
		(net "M_C_CPU1_SA_DQ<4>")
	)
	(segment
		(start 25.432512 -310.143144)
		(end 25.642062 -309.933594)
		(width 0.20066)
		(layer "F.Cu")
		(net "M_C_CPU1_SA_DQ<4>")
	)
	(segment
		(start 25.642062 -309.933594)
		(end 26.20391 -309.933594)
		(width 0.20066)
		(layer "F.Cu")
		(net "M_C_CPU1_SA_DQ<4>")
	)
	(segment
		(start 25.432512 -310.432704)
		(end 25.432512 -310.143144)
		(width 0.20066)
		(layer "F.Cu")
		(net "M_C_CPU1_SA_DQ<4>")
	)
	(segment
		(start 23.228046 -310.366664)
		(end 24.562308 -310.366664)
		(width 0.20066)
		(layer "F.Cu")
		(net "M_C_CPU1_SA_DQ<4>")
	)
	(segment
		(start 85.047074 -283.403294)
		(end 84.730082 -283.720286)
		(width 0.088646)
		(layer "In4.Cu")
		(net "M_C_CPU1_SA_DQ<4>")
	)
	(segment
		(start 57.258204 -310.791606)
		(end 53.63845 -310.791606)
		(width 0.18288)
		(layer "In4.Cu")
		(net "M_C_CPU1_SA_DQ<4>")
	)
	(segment
		(start 66.481452 -307.974238)
		(end 65.282826 -307.974238)
		(width 0.18288)
		(layer "In4.Cu")
		(net "M_C_CPU1_SA_DQ<4>")
	)
	(segment
		(start 48.879506 -311.967372)
		(end 48.719486 -312.127392)
		(width 0.18288)
		(layer "In4.Cu")
		(net "M_C_CPU1_SA_DQ<4>")
	)
	(segment
		(start 35.36696 -310.588406)
		(end 35.36696 -310.111394)
		(width 0.18288)
		(layer "In4.Cu")
		(net "M_C_CPU1_SA_DQ<4>")
	)
	(segment
		(start 89.760044 -276.708616)
		(end 89.760044 -276.718522)
		(width 0.088646)
		(layer "In4.Cu")
		(net "M_C_CPU1_SA_DQ<4>")
	)
	(segment
		(start 33.25241 -308.8894)
		(end 32.90443 -308.8894)
		(width 0.18288)
		(layer "In4.Cu")
		(net "M_C_CPU1_SA_DQ<4>")
	)
	(segment
		(start 80.781144 -287.669224)
		(end 77.183488 -296.353992)
		(width 0.18288)
		(layer "In4.Cu")
		(net "M_C_CPU1_SA_DQ<4>")
	)
	(segment
		(start 48.719486 -312.127392)
		(end 48.346106 -312.127392)
		(width 0.18288)
		(layer "In4.Cu")
		(net "M_C_CPU1_SA_DQ<4>")
	)
	(segment
		(start 52.78755 -311.29986)
		(end 52.78755 -310.951626)
		(width 0.18288)
		(layer "In4.Cu")
		(net "M_C_CPU1_SA_DQ<4>")
	)
	(segment
		(start 59.417458 -309.980076)
		(end 59.27344 -309.836058)
		(width 0.18288)
		(layer "In4.Cu")
		(net "M_C_CPU1_SA_DQ<4>")
	)
	(segment
		(start 63.276988 -309.980076)
		(end 59.417458 -309.980076)
		(width 0.18288)
		(layer "In4.Cu")
		(net "M_C_CPU1_SA_DQ<4>")
	)
	(segment
		(start 69.917564 -304.538126)
		(end 66.481452 -307.974238)
		(width 0.18288)
		(layer "In4.Cu")
		(net "M_C_CPU1_SA_DQ<4>")
	)
	(segment
		(start 69.917564 -303.619916)
		(end 69.917564 -304.538126)
		(width 0.18288)
		(layer "In4.Cu")
		(net "M_C_CPU1_SA_DQ<4>")
	)
	(segment
		(start 88.820244 -278.336502)
		(end 88.820244 -278.346408)
		(width 0.088646)
		(layer "In4.Cu")
		(net "M_C_CPU1_SA_DQ<4>")
	)
	(segment
		(start 50.704242 -310.791606)
		(end 49.854104 -311.641744)
		(width 0.18288)
		(layer "In4.Cu")
		(net "M_C_CPU1_SA_DQ<4>")
	)
	(segment
		(start 35.57016 -310.791606)
		(end 35.36696 -310.588406)
		(width 0.18288)
		(layer "In4.Cu")
		(net "M_C_CPU1_SA_DQ<4>")
	)
	(segment
		(start 53.47843 -311.277)
		(end 53.29555 -311.45988)
		(width 0.18288)
		(layer "In4.Cu")
		(net "M_C_CPU1_SA_DQ<4>")
	)
	(segment
		(start 86.662768 -282.078938)
		(end 86.65845 -282.081478)
		(width 0.088646)
		(layer "In4.Cu")
		(net "M_C_CPU1_SA_DQ<4>")
	)
	(segment
		(start 91.644216 -276.608286)
		(end 91.261692 -276.384258)
		(width 0.088646)
		(layer "In4.Cu")
		(net "M_C_CPU1_SA_DQ<4>")
	)
	(segment
		(start 35.36696 -310.111394)
		(end 35.084512 -309.828946)
		(width 0.18288)
		(layer "In4.Cu")
		(net "M_C_CPU1_SA_DQ<4>")
	)
	(segment
		(start 86.664546 -282.077922)
		(end 86.662768 -282.078938)
		(width 0.088646)
		(layer "In4.Cu")
		(net "M_C_CPU1_SA_DQ<4>")
	)
	(segment
		(start 89.947496 -276.384258)
		(end 89.938606 -276.389338)
		(width 0.088646)
		(layer "In4.Cu")
		(net "M_C_CPU1_SA_DQ<4>")
	)
	(segment
		(start 84.730082 -283.720286)
		(end 80.781144 -287.669224)
		(width 0.18288)
		(layer "In4.Cu")
		(net "M_C_CPU1_SA_DQ<4>")
	)
	(segment
		(start 48.346106 -312.127392)
		(end 48.186086 -311.967372)
		(width 0.18288)
		(layer "In4.Cu")
		(net "M_C_CPU1_SA_DQ<4>")
	)
	(segment
		(start 48.026066 -311.641744)
		(end 44.337986 -311.641744)
		(width 0.18288)
		(layer "In4.Cu")
		(net "M_C_CPU1_SA_DQ<4>")
	)
	(segment
		(start 87.12835 -281.267662)
		(end 87.11946 -281.272742)
		(width 0.088646)
		(layer "In4.Cu")
		(net "M_C_CPU1_SA_DQ<4>")
	)
	(segment
		(start 33.41243 -309.04942)
		(end 33.25241 -308.8894)
		(width 0.18288)
		(layer "In4.Cu")
		(net "M_C_CPU1_SA_DQ<4>")
	)
	(segment
		(start 34.61131 -308.885336)
		(end 34.26333 -308.885336)
		(width 0.18288)
		(layer "In4.Cu")
		(net "M_C_CPU1_SA_DQ<4>")
	)
	(segment
		(start 33.41243 -309.646066)
		(end 33.41243 -309.04942)
		(width 0.18288)
		(layer "In4.Cu")
		(net "M_C_CPU1_SA_DQ<4>")
	)
	(segment
		(start 52.62753 -310.791606)
		(end 50.704242 -310.791606)
		(width 0.18288)
		(layer "In4.Cu")
		(net "M_C_CPU1_SA_DQ<4>")
	)
	(segment
		(start 88.350344 -280.759662)
		(end 88.350344 -280.78811)
		(width 0.088646)
		(layer "In4.Cu")
		(net "M_C_CPU1_SA_DQ<4>")
	)
	(segment
		(start 33.59531 -309.828946)
		(end 33.41243 -309.646066)
		(width 0.18288)
		(layer "In4.Cu")
		(net "M_C_CPU1_SA_DQ<4>")
	)
	(segment
		(start 85.047074 -282.697682)
		(end 85.047074 -283.403294)
		(width 0.088646)
		(layer "In4.Cu")
		(net "M_C_CPU1_SA_DQ<4>")
	)
	(segment
		(start 32.414464 -309.828946)
		(end 31.876746 -310.366664)
		(width 0.18288)
		(layer "In4.Cu")
		(net "M_C_CPU1_SA_DQ<4>")
	)
	(segment
		(start 85.905594 -282.030932)
		(end 85.713824 -282.030932)
		(width 0.088646)
		(layer "In4.Cu")
		(net "M_C_CPU1_SA_DQ<4>")
	)
	(segment
		(start 52.94757 -311.45988)
		(end 52.78755 -311.29986)
		(width 0.18288)
		(layer "In4.Cu")
		(net "M_C_CPU1_SA_DQ<4>")
	)
	(segment
		(start 53.47843 -310.951626)
		(end 53.47843 -311.277)
		(width 0.18288)
		(layer "In4.Cu")
		(net "M_C_CPU1_SA_DQ<4>")
	)
	(segment
		(start 88.067896 -279.639776)
		(end 88.059006 -279.644856)
		(width 0.088646)
		(layer "In4.Cu")
		(net "M_C_CPU1_SA_DQ<4>")
	)
	(segment
		(start 52.78755 -310.951626)
		(end 52.62753 -310.791606)
		(width 0.18288)
		(layer "In4.Cu")
		(net "M_C_CPU1_SA_DQ<4>")
	)
	(segment
		(start 48.186086 -311.801764)
		(end 48.026066 -311.641744)
		(width 0.18288)
		(layer "In4.Cu")
		(net "M_C_CPU1_SA_DQ<4>")
	)
	(segment
		(start 87.51316 -281.273758)
		(end 87.502746 -281.267662)
		(width 0.088646)
		(layer "In4.Cu")
		(net "M_C_CPU1_SA_DQ<4>")
	)
	(segment
		(start 53.63845 -310.791606)
		(end 53.47843 -310.951626)
		(width 0.18288)
		(layer "In4.Cu")
		(net "M_C_CPU1_SA_DQ<4>")
	)
	(segment
		(start 85.713824 -282.030932)
		(end 85.047074 -282.697682)
		(width 0.088646)
		(layer "In4.Cu")
		(net "M_C_CPU1_SA_DQ<4>")
	)
	(segment
		(start 59.27344 -309.836058)
		(end 58.213752 -309.836058)
		(width 0.18288)
		(layer "In4.Cu")
		(net "M_C_CPU1_SA_DQ<4>")
	)
	(segment
		(start 77.183488 -296.353992)
		(end 69.917564 -303.619916)
		(width 0.18288)
		(layer "In4.Cu")
		(net "M_C_CPU1_SA_DQ<4>")
	)
	(segment
		(start 42.072306 -310.791606)
		(end 35.57016 -310.791606)
		(width 0.18288)
		(layer "In4.Cu")
		(net "M_C_CPU1_SA_DQ<4>")
	)
	(segment
		(start 49.854104 -311.641744)
		(end 49.039526 -311.641744)
		(width 0.18288)
		(layer "In4.Cu")
		(net "M_C_CPU1_SA_DQ<4>")
	)
	(segment
		(start 58.213752 -309.836058)
		(end 57.258204 -310.791606)
		(width 0.18288)
		(layer "In4.Cu")
		(net "M_C_CPU1_SA_DQ<4>")
	)
	(segment
		(start 88.059006 -280.283412)
		(end 88.067896 -280.288492)
		(width 0.088646)
		(layer "In4.Cu")
		(net "M_C_CPU1_SA_DQ<4>")
	)
	(segment
		(start 34.10331 -309.668926)
		(end 33.94329 -309.828946)
		(width 0.18288)
		(layer "In4.Cu")
		(net "M_C_CPU1_SA_DQ<4>")
	)
	(segment
		(start 32.72155 -309.07228)
		(end 32.72155 -309.668926)
		(width 0.18288)
		(layer "In4.Cu")
		(net "M_C_CPU1_SA_DQ<4>")
	)
	(segment
		(start 34.26333 -308.885336)
		(end 34.10331 -309.045356)
		(width 0.18288)
		(layer "In4.Cu")
		(net "M_C_CPU1_SA_DQ<4>")
	)
	(segment
		(start 89.290398 -277.513796)
		(end 89.290398 -277.536656)
		(width 0.088646)
		(layer "In4.Cu")
		(net "M_C_CPU1_SA_DQ<4>")
	)
	(segment
		(start 34.95421 -309.828946)
		(end 34.79419 -309.668926)
		(width 0.18288)
		(layer "In4.Cu")
		(net "M_C_CPU1_SA_DQ<4>")
	)
	(segment
		(start 48.879506 -311.801764)
		(end 48.879506 -311.967372)
		(width 0.18288)
		(layer "In4.Cu")
		(net "M_C_CPU1_SA_DQ<4>")
	)
	(segment
		(start 65.282826 -307.974238)
		(end 63.276988 -309.980076)
		(width 0.18288)
		(layer "In4.Cu")
		(net "M_C_CPU1_SA_DQ<4>")
	)
	(segment
		(start 88.537796 -278.82596)
		(end 88.528906 -278.83104)
		(width 0.088646)
		(layer "In4.Cu")
		(net "M_C_CPU1_SA_DQ<4>")
	)
	(segment
		(start 32.72155 -309.668926)
		(end 32.56153 -309.828946)
		(width 0.18288)
		(layer "In4.Cu")
		(net "M_C_CPU1_SA_DQ<4>")
	)
	(segment
		(start 34.79419 -309.068216)
		(end 34.61131 -308.885336)
		(width 0.18288)
		(layer "In4.Cu")
		(net "M_C_CPU1_SA_DQ<4>")
	)
	(segment
		(start 53.29555 -311.45988)
		(end 52.94757 -311.45988)
		(width 0.18288)
		(layer "In4.Cu")
		(net "M_C_CPU1_SA_DQ<4>")
	)
	(segment
		(start 33.94329 -309.828946)
		(end 33.59531 -309.828946)
		(width 0.18288)
		(layer "In4.Cu")
		(net "M_C_CPU1_SA_DQ<4>")
	)
	(segment
		(start 44.140374 -311.444132)
		(end 42.724832 -311.444132)
		(width 0.18288)
		(layer "In4.Cu")
		(net "M_C_CPU1_SA_DQ<4>")
	)
	(segment
		(start 34.10331 -309.045356)
		(end 34.10331 -309.668926)
		(width 0.18288)
		(layer "In4.Cu")
		(net "M_C_CPU1_SA_DQ<4>")
	)
	(segment
		(start 34.79419 -309.668926)
		(end 34.79419 -309.068216)
		(width 0.18288)
		(layer "In4.Cu")
		(net "M_C_CPU1_SA_DQ<4>")
	)
	(segment
		(start 32.56153 -309.828946)
		(end 32.414464 -309.828946)
		(width 0.18288)
		(layer "In4.Cu")
		(net "M_C_CPU1_SA_DQ<4>")
	)
	(segment
		(start 88.350344 -279.150318)
		(end 88.350344 -279.160224)
		(width 0.088646)
		(layer "In4.Cu")
		(net "M_C_CPU1_SA_DQ<4>")
	)
	(segment
		(start 49.039526 -311.641744)
		(end 48.879506 -311.801764)
		(width 0.18288)
		(layer "In4.Cu")
		(net "M_C_CPU1_SA_DQ<4>")
	)
	(segment
		(start 48.186086 -311.967372)
		(end 48.186086 -311.801764)
		(width 0.18288)
		(layer "In4.Cu")
		(net "M_C_CPU1_SA_DQ<4>")
	)
	(segment
		(start 44.337986 -311.641744)
		(end 44.140374 -311.444132)
		(width 0.18288)
		(layer "In4.Cu")
		(net "M_C_CPU1_SA_DQ<4>")
	)
	(segment
		(start 42.724832 -311.444132)
		(end 42.072306 -310.791606)
		(width 0.18288)
		(layer "In4.Cu")
		(net "M_C_CPU1_SA_DQ<4>")
	)
	(segment
		(start 35.084512 -309.828946)
		(end 34.95421 -309.828946)
		(width 0.18288)
		(layer "In4.Cu")
		(net "M_C_CPU1_SA_DQ<4>")
	)
	(segment
		(start 89.007696 -278.012144)
		(end 88.998806 -278.017224)
		(width 0.088646)
		(layer "In4.Cu")
		(net "M_C_CPU1_SA_DQ<4>")
	)
	(segment
		(start 32.90443 -308.8894)
		(end 32.72155 -309.07228)
		(width 0.18288)
		(layer "In4.Cu")
		(net "M_C_CPU1_SA_DQ<4>")
	)
	(arc
		(start 88.350344 -279.160224)
		(mid 88.272233 -279.437173)
		(end 88.067896 -279.639776)
		(width 0.088646)
		(layer "In4.Cu")
		(net "M_C_CPU1_SA_DQ<4>")
	)
	(arc
		(start 86.103206 -282.087574)
		(mid 86.008362 -282.045423)
		(end 85.905594 -282.030932)
		(width 0.088646)
		(layer "In4.Cu")
		(net "M_C_CPU1_SA_DQ<4>")
	)
	(arc
		(start 88.528906 -278.83104)
		(mid 88.397992 -278.9674)
		(end 88.350344 -279.150318)
		(width 0.088646)
		(layer "In4.Cu")
		(net "M_C_CPU1_SA_DQ<4>")
	)
	(arc
		(start 88.067896 -281.267662)
		(mid 87.791337 -281.343405)
		(end 87.51316 -281.273758)
		(width 0.088646)
		(layer "In4.Cu")
		(net "M_C_CPU1_SA_DQ<4>")
	)
	(arc
		(start 87.502746 -281.267662)
		(mid 87.315548 -281.217519)
		(end 87.12835 -281.267662)
		(width 0.088646)
		(layer "In4.Cu")
		(net "M_C_CPU1_SA_DQ<4>")
	)
	(arc
		(start 89.938606 -276.389338)
		(mid 89.807692 -276.525698)
		(end 89.760044 -276.708616)
		(width 0.088646)
		(layer "In4.Cu")
		(net "M_C_CPU1_SA_DQ<4>")
	)
	(arc
		(start 90.321892 -276.384258)
		(mid 90.134694 -276.334115)
		(end 89.947496 -276.384258)
		(width 0.088646)
		(layer "In4.Cu")
		(net "M_C_CPU1_SA_DQ<4>")
	)
	(arc
		(start 88.998806 -278.017224)
		(mid 88.867892 -278.153584)
		(end 88.820244 -278.336502)
		(width 0.088646)
		(layer "In4.Cu")
		(net "M_C_CPU1_SA_DQ<4>")
	)
	(arc
		(start 92.014548 -276.708616)
		(mid 91.822692 -276.683133)
		(end 91.644216 -276.608286)
		(width 0.088646)
		(layer "In4.Cu")
		(net "M_C_CPU1_SA_DQ<4>")
	)
	(arc
		(start 91.261692 -276.384258)
		(mid 91.074494 -276.334115)
		(end 90.887296 -276.384258)
		(width 0.088646)
		(layer "In4.Cu")
		(net "M_C_CPU1_SA_DQ<4>")
	)
	(arc
		(start 87.11946 -281.272742)
		(mid 86.988546 -281.409102)
		(end 86.940898 -281.59202)
		(width 0.088646)
		(layer "In4.Cu")
		(net "M_C_CPU1_SA_DQ<4>")
	)
	(arc
		(start 86.65845 -282.081478)
		(mid 86.381637 -282.157348)
		(end 86.103206 -282.087574)
		(width 0.088646)
		(layer "In4.Cu")
		(net "M_C_CPU1_SA_DQ<4>")
	)
	(arc
		(start 86.940898 -281.59202)
		(mid 86.866982 -281.871522)
		(end 86.664546 -282.077922)
		(width 0.088646)
		(layer "In4.Cu")
		(net "M_C_CPU1_SA_DQ<4>")
	)
	(arc
		(start 89.290398 -277.536656)
		(mid 89.211179 -277.811341)
		(end 89.007696 -278.012144)
		(width 0.088646)
		(layer "In4.Cu")
		(net "M_C_CPU1_SA_DQ<4>")
	)
	(arc
		(start 90.887296 -276.384258)
		(mid 90.604594 -276.460034)
		(end 90.321892 -276.384258)
		(width 0.088646)
		(layer "In4.Cu")
		(net "M_C_CPU1_SA_DQ<4>")
	)
	(arc
		(start 88.067896 -280.288492)
		(mid 88.270182 -280.487473)
		(end 88.350344 -280.759662)
		(width 0.088646)
		(layer "In4.Cu")
		(net "M_C_CPU1_SA_DQ<4>")
	)
	(arc
		(start 89.477596 -277.198074)
		(mid 89.342663 -277.331428)
		(end 89.290398 -277.513796)
		(width 0.088646)
		(layer "In4.Cu")
		(net "M_C_CPU1_SA_DQ<4>")
	)
	(arc
		(start 88.059006 -279.644856)
		(mid 87.880409 -279.964134)
		(end 88.059006 -280.283412)
		(width 0.088646)
		(layer "In4.Cu")
		(net "M_C_CPU1_SA_DQ<4>")
	)
	(arc
		(start 88.820244 -278.346408)
		(mid 88.742133 -278.623357)
		(end 88.537796 -278.82596)
		(width 0.088646)
		(layer "In4.Cu")
		(net "M_C_CPU1_SA_DQ<4>")
	)
	(arc
		(start 88.350344 -280.78811)
		(mid 88.272233 -281.065059)
		(end 88.067896 -281.267662)
		(width 0.088646)
		(layer "In4.Cu")
		(net "M_C_CPU1_SA_DQ<4>")
	)
	(arc
		(start 89.760044 -276.718522)
		(mid 89.681933 -276.995471)
		(end 89.477596 -277.198074)
		(width 0.088646)
		(layer "In4.Cu")
		(net "M_C_CPU1_SA_DQ<4>")
	)
	(segment
		(start 29.151326 -313.892692)
		(end 29.151326 -314.06338)
		(width 0.20066)
		(layer "F.Cu")
		(net "M_C_CPU1_SA_DQ<3>")
	)
	(segment
		(start 33.848294 -313.974226)
		(end 34.055812 -313.766708)
		(width 0.20066)
		(layer "F.Cu")
		(net "M_C_CPU1_SA_DQ<3>")
	)
	(segment
		(start 29.025342 -313.766708)
		(end 29.151326 -313.892692)
		(width 0.20066)
		(layer "F.Cu")
		(net "M_C_CPU1_SA_DQ<3>")
	)
	(segment
		(start 29.647642 -314.205874)
		(end 29.661866 -314.19165)
		(width 0.101854)
		(layer "F.Cu")
		(net "M_C_CPU1_SA_DQ<3>")
	)
	(segment
		(start 35.976814 -313.766708)
		(end 34.871914 -313.766708)
		(width 0.20066)
		(layer "F.Cu")
		(net "M_C_CPU1_SA_DQ<3>")
	)
	(segment
		(start 32.51708 -314.19165)
		(end 32.666178 -314.042552)
		(width 0.20066)
		(layer "F.Cu")
		(net "M_C_CPU1_SA_DQ<3>")
	)
	(segment
		(start 29.29382 -314.205874)
		(end 29.647642 -314.205874)
		(width 0.20066)
		(layer "F.Cu")
		(net "M_C_CPU1_SA_DQ<3>")
	)
	(segment
		(start 93.893894 -277.800562)
		(end 93.893894 -278.336248)
		(width 0.20066)
		(layer "F.Cu")
		(net "M_C_CPU1_SA_DQ<3>")
	)
	(segment
		(start 29.899864 -314.19165)
		(end 31.972758 -314.19165)
		(width 0.1016)
		(layer "F.Cu")
		(net "M_C_CPU1_SA_DQ<3>")
	)
	(segment
		(start 93.893894 -278.336248)
		(end 93.894148 -278.336502)
		(width 0.20066)
		(layer "F.Cu")
		(net "M_C_CPU1_SA_DQ<3>")
	)
	(segment
		(start 32.794702 -313.76239)
		(end 33.189926 -313.76239)
		(width 0.20066)
		(layer "F.Cu")
		(net "M_C_CPU1_SA_DQ<3>")
	)
	(segment
		(start 29.151326 -314.06338)
		(end 29.29382 -314.205874)
		(width 0.20066)
		(layer "F.Cu")
		(net "M_C_CPU1_SA_DQ<3>")
	)
	(segment
		(start 33.189926 -313.76239)
		(end 33.401762 -313.974226)
		(width 0.20066)
		(layer "F.Cu")
		(net "M_C_CPU1_SA_DQ<3>")
	)
	(segment
		(start 29.661866 -314.19165)
		(end 29.899864 -314.19165)
		(width 0.101854)
		(layer "F.Cu")
		(net "M_C_CPU1_SA_DQ<3>")
	)
	(segment
		(start 34.055812 -313.766708)
		(end 34.871914 -313.766708)
		(width 0.20066)
		(layer "F.Cu")
		(net "M_C_CPU1_SA_DQ<3>")
	)
	(segment
		(start 31.972758 -314.19165)
		(end 32.51708 -314.19165)
		(width 0.20066)
		(layer "F.Cu")
		(net "M_C_CPU1_SA_DQ<3>")
	)
	(segment
		(start 33.401762 -313.974226)
		(end 33.848294 -313.974226)
		(width 0.20066)
		(layer "F.Cu")
		(net "M_C_CPU1_SA_DQ<3>")
	)
	(segment
		(start 32.666178 -313.890914)
		(end 32.794702 -313.76239)
		(width 0.20066)
		(layer "F.Cu")
		(net "M_C_CPU1_SA_DQ<3>")
	)
	(segment
		(start 32.666178 -314.042552)
		(end 32.666178 -313.890914)
		(width 0.20066)
		(layer "F.Cu")
		(net "M_C_CPU1_SA_DQ<3>")
	)
	(segment
		(start 27.328114 -313.766708)
		(end 29.025342 -313.766708)
		(width 0.20066)
		(layer "F.Cu")
		(net "M_C_CPU1_SA_DQ<3>")
	)
	(segment
		(start 60.307474 -314.787026)
		(end 59.865514 -314.787026)
		(width 0.18288)
		(layer "In4.Cu")
		(net "M_C_CPU1_SA_DQ<3>")
	)
	(segment
		(start 46.220126 -316.74181)
		(end 45.369988 -315.891672)
		(width 0.18288)
		(layer "In4.Cu")
		(net "M_C_CPU1_SA_DQ<3>")
	)
	(segment
		(start 72.482964 -304.508662)
		(end 72.482964 -306.631848)
		(width 0.18288)
		(layer "In4.Cu")
		(net "M_C_CPU1_SA_DQ<3>")
	)
	(segment
		(start 60.781946 -314.312554)
		(end 60.307474 -314.787026)
		(width 0.18288)
		(layer "In4.Cu")
		(net "M_C_CPU1_SA_DQ<3>")
	)
	(segment
		(start 53.152802 -315.454538)
		(end 52.992782 -315.614558)
		(width 0.18288)
		(layer "In4.Cu")
		(net "M_C_CPU1_SA_DQ<3>")
	)
	(segment
		(start 60.852558 -313.163966)
		(end 60.626498 -313.163966)
		(width 0.18288)
		(layer "In4.Cu")
		(net "M_C_CPU1_SA_DQ<3>")
	)
	(segment
		(start 45.369988 -315.891672)
		(end 41.304972 -315.891672)
		(width 0.18288)
		(layer "In4.Cu")
		(net "M_C_CPU1_SA_DQ<3>")
	)
	(segment
		(start 62.260988 -312.833512)
		(end 61.513466 -313.581034)
		(width 0.18288)
		(layer "In4.Cu")
		(net "M_C_CPU1_SA_DQ<3>")
	)
	(segment
		(start 79.389224 -297.602402)
		(end 72.482964 -304.508662)
		(width 0.18288)
		(layer "In4.Cu")
		(net "M_C_CPU1_SA_DQ<3>")
	)
	(segment
		(start 90.792046 -282.081478)
		(end 90.800936 -282.086558)
		(width 0.088646)
		(layer "In4.Cu")
		(net "M_C_CPU1_SA_DQ<3>")
	)
	(segment
		(start 61.513466 -313.581034)
		(end 61.269626 -313.581034)
		(width 0.18288)
		(layer "In4.Cu")
		(net "M_C_CPU1_SA_DQ<3>")
	)
	(segment
		(start 52.076604 -315.999368)
		(end 51.334162 -316.74181)
		(width 0.18288)
		(layer "In4.Cu")
		(net "M_C_CPU1_SA_DQ<3>")
	)
	(segment
		(start 62.737746 -312.833512)
		(end 62.260988 -312.833512)
		(width 0.18288)
		(layer "In4.Cu")
		(net "M_C_CPU1_SA_DQ<3>")
	)
	(segment
		(start 56.590184 -315.184536)
		(end 55.470044 -315.184536)
		(width 0.18288)
		(layer "In4.Cu")
		(net "M_C_CPU1_SA_DQ<3>")
	)
	(segment
		(start 63.410592 -313.506358)
		(end 62.737746 -312.833512)
		(width 0.18288)
		(layer "In4.Cu")
		(net "M_C_CPU1_SA_DQ<3>")
	)
	(segment
		(start 90.979244 -279.140412)
		(end 90.979244 -279.150318)
		(width 0.088646)
		(layer "In4.Cu")
		(net "M_C_CPU1_SA_DQ<3>")
	)
	(segment
		(start 91.82735 -278.012144)
		(end 91.827096 -278.012398)
		(width 0.088646)
		(layer "In4.Cu")
		(net "M_C_CPU1_SA_DQ<3>")
	)
	(segment
		(start 54.655212 -315.999368)
		(end 53.843682 -315.999368)
		(width 0.18288)
		(layer "In4.Cu")
		(net "M_C_CPU1_SA_DQ<3>")
	)
	(segment
		(start 90.509344 -283.205682)
		(end 90.509344 -283.219906)
		(width 0.088646)
		(layer "In4.Cu")
		(net "M_C_CPU1_SA_DQ<3>")
	)
	(segment
		(start 52.992782 -315.614558)
		(end 52.992782 -315.839348)
		(width 0.18288)
		(layer "In4.Cu")
		(net "M_C_CPU1_SA_DQ<3>")
	)
	(segment
		(start 60.626498 -313.163966)
		(end 60.380372 -313.410092)
		(width 0.18288)
		(layer "In4.Cu")
		(net "M_C_CPU1_SA_DQ<3>")
	)
	(segment
		(start 90.330782 -283.539184)
		(end 90.321892 -283.544264)
		(width 0.088646)
		(layer "In4.Cu")
		(net "M_C_CPU1_SA_DQ<3>")
	)
	(segment
		(start 88.912446 -284.35808)
		(end 88.90635 -284.361636)
		(width 0.088646)
		(layer "In4.Cu")
		(net "M_C_CPU1_SA_DQ<3>")
	)
	(segment
		(start 53.683662 -315.839348)
		(end 53.683662 -315.637418)
		(width 0.18288)
		(layer "In4.Cu")
		(net "M_C_CPU1_SA_DQ<3>")
	)
	(segment
		(start 88.159844 -285.651448)
		(end 88.159844 -285.661354)
		(width 0.088646)
		(layer "In4.Cu")
		(net "M_C_CPU1_SA_DQ<3>")
	)
	(segment
		(start 53.500782 -315.454538)
		(end 53.152802 -315.454538)
		(width 0.18288)
		(layer "In4.Cu")
		(net "M_C_CPU1_SA_DQ<3>")
	)
	(segment
		(start 91.270836 -280.283412)
		(end 91.261946 -280.288492)
		(width 0.088646)
		(layer "In4.Cu")
		(net "M_C_CPU1_SA_DQ<3>")
	)
	(segment
		(start 66.960242 -312.15457)
		(end 65.100454 -312.924698)
		(width 0.18288)
		(layer "In4.Cu")
		(net "M_C_CPU1_SA_DQ<3>")
	)
	(segment
		(start 39.768526 -314.355226)
		(end 36.565332 -314.355226)
		(width 0.18288)
		(layer "In4.Cu")
		(net "M_C_CPU1_SA_DQ<3>")
	)
	(segment
		(start 88.451182 -285.166816)
		(end 88.442292 -285.171896)
		(width 0.088646)
		(layer "In4.Cu")
		(net "M_C_CPU1_SA_DQ<3>")
	)
	(segment
		(start 55.470044 -315.184536)
		(end 54.655212 -315.999368)
		(width 0.18288)
		(layer "In4.Cu")
		(net "M_C_CPU1_SA_DQ<3>")
	)
	(segment
		(start 91.25585 -279.63622)
		(end 91.261946 -279.639776)
		(width 0.088646)
		(layer "In4.Cu")
		(net "M_C_CPU1_SA_DQ<3>")
	)
	(segment
		(start 85.240876 -287.044892)
		(end 84.944458 -287.044892)
		(width 0.088646)
		(layer "In4.Cu")
		(net "M_C_CPU1_SA_DQ<3>")
	)
	(segment
		(start 52.992782 -315.839348)
		(end 52.832762 -315.999368)
		(width 0.18288)
		(layer "In4.Cu")
		(net "M_C_CPU1_SA_DQ<3>")
	)
	(segment
		(start 90.792046 -282.730194)
		(end 90.791792 -282.730194)
		(width 0.088646)
		(layer "In4.Cu")
		(net "M_C_CPU1_SA_DQ<3>")
	)
	(segment
		(start 65.100454 -312.924698)
		(end 64.518794 -313.506358)
		(width 0.18288)
		(layer "In4.Cu")
		(net "M_C_CPU1_SA_DQ<3>")
	)
	(segment
		(start 41.304972 -315.891672)
		(end 39.768526 -314.355226)
		(width 0.18288)
		(layer "In4.Cu")
		(net "M_C_CPU1_SA_DQ<3>")
	)
	(segment
		(start 92.216478 -278.02078)
		(end 92.201746 -278.012144)
		(width 0.088646)
		(layer "In4.Cu")
		(net "M_C_CPU1_SA_DQ<3>")
	)
	(segment
		(start 89.099644 -284.023816)
		(end 89.099644 -284.042358)
		(width 0.088646)
		(layer "In4.Cu")
		(net "M_C_CPU1_SA_DQ<3>")
	)
	(segment
		(start 91.261946 -279.639776)
		(end 91.270836 -279.644856)
		(width 0.088646)
		(layer "In4.Cu")
		(net "M_C_CPU1_SA_DQ<3>")
	)
	(segment
		(start 60.781946 -314.070746)
		(end 60.781946 -314.312554)
		(width 0.18288)
		(layer "In4.Cu")
		(net "M_C_CPU1_SA_DQ<3>")
	)
	(segment
		(start 91.270582 -278.65578)
		(end 91.261692 -278.66086)
		(width 0.088646)
		(layer "In4.Cu")
		(net "M_C_CPU1_SA_DQ<3>")
	)
	(segment
		(start 93.45422 -278.129238)
		(end 93.172026 -277.982426)
		(width 0.088646)
		(layer "In4.Cu")
		(net "M_C_CPU1_SA_DQ<3>")
	)
	(segment
		(start 60.380372 -313.669172)
		(end 60.781946 -314.070746)
		(width 0.18288)
		(layer "In4.Cu")
		(net "M_C_CPU1_SA_DQ<3>")
	)
	(segment
		(start 60.380372 -313.410092)
		(end 60.380372 -313.669172)
		(width 0.18288)
		(layer "In4.Cu")
		(net "M_C_CPU1_SA_DQ<3>")
	)
	(segment
		(start 53.843682 -315.999368)
		(end 53.683662 -315.839348)
		(width 0.18288)
		(layer "In4.Cu")
		(net "M_C_CPU1_SA_DQ<3>")
	)
	(segment
		(start 87.981282 -285.980632)
		(end 87.972392 -285.985712)
		(width 0.088646)
		(layer "In4.Cu")
		(net "M_C_CPU1_SA_DQ<3>")
	)
	(segment
		(start 51.334162 -316.74181)
		(end 46.220126 -316.74181)
		(width 0.18288)
		(layer "In4.Cu")
		(net "M_C_CPU1_SA_DQ<3>")
	)
	(segment
		(start 53.683662 -315.637418)
		(end 53.500782 -315.454538)
		(width 0.18288)
		(layer "In4.Cu")
		(net "M_C_CPU1_SA_DQ<3>")
	)
	(segment
		(start 91.639898 -278.336502)
		(end 91.41968 -278.482044)
		(width 0.088646)
		(layer "In4.Cu")
		(net "M_C_CPU1_SA_DQ<3>")
	)
	(segment
		(start 84.944458 -287.044892)
		(end 84.644484 -287.044892)
		(width 0.18288)
		(layer "In4.Cu")
		(net "M_C_CPU1_SA_DQ<3>")
	)
	(segment
		(start 72.482964 -306.631848)
		(end 66.960242 -312.15457)
		(width 0.18288)
		(layer "In4.Cu")
		(net "M_C_CPU1_SA_DQ<3>")
	)
	(segment
		(start 90.509344 -281.582114)
		(end 90.509344 -281.59202)
		(width 0.088646)
		(layer "In4.Cu")
		(net "M_C_CPU1_SA_DQ<3>")
	)
	(segment
		(start 36.565332 -314.355226)
		(end 35.976814 -313.766708)
		(width 0.18288)
		(layer "In4.Cu")
		(net "M_C_CPU1_SA_DQ<3>")
	)
	(segment
		(start 90.800936 -282.725114)
		(end 90.792046 -282.730194)
		(width 0.088646)
		(layer "In4.Cu")
		(net "M_C_CPU1_SA_DQ<3>")
	)
	(segment
		(start 83.140296 -288.54908)
		(end 79.389224 -297.602402)
		(width 0.18288)
		(layer "In4.Cu")
		(net "M_C_CPU1_SA_DQ<3>")
	)
	(segment
		(start 90.78595 -282.077922)
		(end 90.792046 -282.081478)
		(width 0.088646)
		(layer "In4.Cu")
		(net "M_C_CPU1_SA_DQ<3>")
	)
	(segment
		(start 59.031124 -313.952636)
		(end 57.822084 -313.952636)
		(width 0.18288)
		(layer "In4.Cu")
		(net "M_C_CPU1_SA_DQ<3>")
	)
	(segment
		(start 61.269626 -313.581034)
		(end 60.852558 -313.163966)
		(width 0.18288)
		(layer "In4.Cu")
		(net "M_C_CPU1_SA_DQ<3>")
	)
	(segment
		(start 57.822084 -313.952636)
		(end 56.590184 -315.184536)
		(width 0.18288)
		(layer "In4.Cu")
		(net "M_C_CPU1_SA_DQ<3>")
	)
	(segment
		(start 85.810344 -286.456882)
		(end 85.810344 -286.475424)
		(width 0.088646)
		(layer "In4.Cu")
		(net "M_C_CPU1_SA_DQ<3>")
	)
	(segment
		(start 84.644484 -287.044892)
		(end 83.140296 -288.54908)
		(width 0.18288)
		(layer "In4.Cu")
		(net "M_C_CPU1_SA_DQ<3>")
	)
	(segment
		(start 90.800682 -281.097482)
		(end 90.791792 -281.102562)
		(width 0.088646)
		(layer "In4.Cu")
		(net "M_C_CPU1_SA_DQ<3>")
	)
	(segment
		(start 52.832762 -315.999368)
		(end 52.076604 -315.999368)
		(width 0.18288)
		(layer "In4.Cu")
		(net "M_C_CPU1_SA_DQ<3>")
	)
	(segment
		(start 90.979244 -280.76398)
		(end 90.979244 -280.778204)
		(width 0.088646)
		(layer "In4.Cu")
		(net "M_C_CPU1_SA_DQ<3>")
	)
	(segment
		(start 85.435694 -286.850074)
		(end 85.240876 -287.044892)
		(width 0.088646)
		(layer "In4.Cu")
		(net "M_C_CPU1_SA_DQ<3>")
	)
	(segment
		(start 64.518794 -313.506358)
		(end 63.410592 -313.506358)
		(width 0.18288)
		(layer "In4.Cu")
		(net "M_C_CPU1_SA_DQ<3>")
	)
	(segment
		(start 59.865514 -314.787026)
		(end 59.031124 -313.952636)
		(width 0.18288)
		(layer "In4.Cu")
		(net "M_C_CPU1_SA_DQ<3>")
	)
	(arc
		(start 91.261946 -280.288492)
		(mid 91.058465 -280.489296)
		(end 90.979244 -280.76398)
		(width 0.088646)
		(layer "In4.Cu")
		(net "M_C_CPU1_SA_DQ<3>")
	)
	(arc
		(start 89.382092 -283.544264)
		(mid 89.177757 -283.746869)
		(end 89.099644 -284.023816)
		(width 0.088646)
		(layer "In4.Cu")
		(net "M_C_CPU1_SA_DQ<3>")
	)
	(arc
		(start 90.979244 -279.150318)
		(mid 91.053235 -279.429884)
		(end 91.25585 -279.63622)
		(width 0.088646)
		(layer "In4.Cu")
		(net "M_C_CPU1_SA_DQ<3>")
	)
	(arc
		(start 88.159844 -285.661354)
		(mid 88.112165 -285.844254)
		(end 87.981282 -285.980632)
		(width 0.088646)
		(layer "In4.Cu")
		(net "M_C_CPU1_SA_DQ<3>")
	)
	(arc
		(start 93.172026 -277.982426)
		(mid 92.927269 -277.929333)
		(end 92.689426 -278.007826)
		(width 0.088646)
		(layer "In4.Cu")
		(net "M_C_CPU1_SA_DQ<3>")
	)
	(arc
		(start 90.791792 -282.730194)
		(mid 90.588487 -282.93106)
		(end 90.509344 -283.205682)
		(width 0.088646)
		(layer "In4.Cu")
		(net "M_C_CPU1_SA_DQ<3>")
	)
	(arc
		(start 87.032592 -285.985712)
		(mid 86.845394 -286.035855)
		(end 86.658196 -285.985712)
		(width 0.088646)
		(layer "In4.Cu")
		(net "M_C_CPU1_SA_DQ<3>")
	)
	(arc
		(start 91.41968 -278.482044)
		(mid 91.358704 -278.580553)
		(end 91.270582 -278.65578)
		(width 0.088646)
		(layer "In4.Cu")
		(net "M_C_CPU1_SA_DQ<3>")
	)
	(arc
		(start 92.201746 -278.012144)
		(mid 92.014548 -277.962001)
		(end 91.82735 -278.012144)
		(width 0.088646)
		(layer "In4.Cu")
		(net "M_C_CPU1_SA_DQ<3>")
	)
	(arc
		(start 88.442292 -285.171896)
		(mid 88.237957 -285.374501)
		(end 88.159844 -285.651448)
		(width 0.088646)
		(layer "In4.Cu")
		(net "M_C_CPU1_SA_DQ<3>")
	)
	(arc
		(start 91.261692 -278.66086)
		(mid 91.057357 -278.863465)
		(end 90.979244 -279.140412)
		(width 0.088646)
		(layer "In4.Cu")
		(net "M_C_CPU1_SA_DQ<3>")
	)
	(arc
		(start 86.092792 -285.985712)
		(mid 85.890506 -286.184693)
		(end 85.810344 -286.456882)
		(width 0.088646)
		(layer "In4.Cu")
		(net "M_C_CPU1_SA_DQ<3>")
	)
	(arc
		(start 90.791792 -281.102562)
		(mid 90.587457 -281.305167)
		(end 90.509344 -281.582114)
		(width 0.088646)
		(layer "In4.Cu")
		(net "M_C_CPU1_SA_DQ<3>")
	)
	(arc
		(start 89.099644 -284.042358)
		(mid 89.047374 -284.224723)
		(end 88.912446 -284.35808)
		(width 0.088646)
		(layer "In4.Cu")
		(net "M_C_CPU1_SA_DQ<3>")
	)
	(arc
		(start 93.894148 -278.336502)
		(mid 93.672141 -278.237206)
		(end 93.45422 -278.129238)
		(width 0.088646)
		(layer "In4.Cu")
		(net "M_C_CPU1_SA_DQ<3>")
	)
	(arc
		(start 90.509344 -283.219906)
		(mid 90.461665 -283.402806)
		(end 90.330782 -283.539184)
		(width 0.088646)
		(layer "In4.Cu")
		(net "M_C_CPU1_SA_DQ<3>")
	)
	(arc
		(start 90.979244 -280.778204)
		(mid 90.931565 -280.961104)
		(end 90.800682 -281.097482)
		(width 0.088646)
		(layer "In4.Cu")
		(net "M_C_CPU1_SA_DQ<3>")
	)
	(arc
		(start 91.270836 -279.644856)
		(mid 91.449433 -279.964134)
		(end 91.270836 -280.283412)
		(width 0.088646)
		(layer "In4.Cu")
		(net "M_C_CPU1_SA_DQ<3>")
	)
	(arc
		(start 88.629744 -284.847538)
		(mid 88.582065 -285.030438)
		(end 88.451182 -285.166816)
		(width 0.088646)
		(layer "In4.Cu")
		(net "M_C_CPU1_SA_DQ<3>")
	)
	(arc
		(start 92.689426 -278.007826)
		(mid 92.454802 -278.082027)
		(end 92.216478 -278.02078)
		(width 0.088646)
		(layer "In4.Cu")
		(net "M_C_CPU1_SA_DQ<3>")
	)
	(arc
		(start 90.800936 -282.086558)
		(mid 90.979533 -282.405836)
		(end 90.800936 -282.725114)
		(width 0.088646)
		(layer "In4.Cu")
		(net "M_C_CPU1_SA_DQ<3>")
	)
	(arc
		(start 85.631782 -286.794702)
		(mid 85.537572 -286.835964)
		(end 85.435694 -286.850074)
		(width 0.088646)
		(layer "In4.Cu")
		(net "M_C_CPU1_SA_DQ<3>")
	)
	(arc
		(start 87.597996 -285.985712)
		(mid 87.315294 -285.90997)
		(end 87.032592 -285.985712)
		(width 0.088646)
		(layer "In4.Cu")
		(net "M_C_CPU1_SA_DQ<3>")
	)
	(arc
		(start 85.810344 -286.475424)
		(mid 85.762665 -286.658324)
		(end 85.631782 -286.794702)
		(width 0.088646)
		(layer "In4.Cu")
		(net "M_C_CPU1_SA_DQ<3>")
	)
	(arc
		(start 90.321892 -283.544264)
		(mid 90.134694 -283.594407)
		(end 89.947496 -283.544264)
		(width 0.088646)
		(layer "In4.Cu")
		(net "M_C_CPU1_SA_DQ<3>")
	)
	(arc
		(start 87.972392 -285.985712)
		(mid 87.785194 -286.035855)
		(end 87.597996 -285.985712)
		(width 0.088646)
		(layer "In4.Cu")
		(net "M_C_CPU1_SA_DQ<3>")
	)
	(arc
		(start 86.658196 -285.985712)
		(mid 86.375494 -285.90997)
		(end 86.092792 -285.985712)
		(width 0.088646)
		(layer "In4.Cu")
		(net "M_C_CPU1_SA_DQ<3>")
	)
	(arc
		(start 90.509344 -281.59202)
		(mid 90.583335 -281.871586)
		(end 90.78595 -282.077922)
		(width 0.088646)
		(layer "In4.Cu")
		(net "M_C_CPU1_SA_DQ<3>")
	)
	(arc
		(start 89.947496 -283.544264)
		(mid 89.664794 -283.468488)
		(end 89.382092 -283.544264)
		(width 0.088646)
		(layer "In4.Cu")
		(net "M_C_CPU1_SA_DQ<3>")
	)
	(arc
		(start 88.90635 -284.361636)
		(mid 88.703763 -284.567987)
		(end 88.629744 -284.847538)
		(width 0.088646)
		(layer "In4.Cu")
		(net "M_C_CPU1_SA_DQ<3>")
	)
	(arc
		(start 91.827096 -278.012398)
		(mid 91.690051 -278.149358)
		(end 91.639898 -278.336502)
		(width 0.088646)
		(layer "In4.Cu")
		(net "M_C_CPU1_SA_DQ<3>")
	)
	(segment
		(start 29.151326 -279.89276)
		(end 29.151326 -280.063448)
		(width 0.20066)
		(layer "F.Cu")
		(net "M_C_CPU1_SA_DQ<31>")
	)
	(segment
		(start 29.647642 -280.205942)
		(end 29.661866 -280.191718)
		(width 0.101854)
		(layer "F.Cu")
		(net "M_C_CPU1_SA_DQ<31>")
	)
	(segment
		(start 34.055812 -279.766776)
		(end 34.871914 -279.766776)
		(width 0.20066)
		(layer "F.Cu")
		(net "M_C_CPU1_SA_DQ<31>")
	)
	(segment
		(start 29.151326 -280.063448)
		(end 29.29382 -280.205942)
		(width 0.20066)
		(layer "F.Cu")
		(net "M_C_CPU1_SA_DQ<31>")
	)
	(segment
		(start 33.189926 -279.762458)
		(end 33.401762 -279.974294)
		(width 0.20066)
		(layer "F.Cu")
		(net "M_C_CPU1_SA_DQ<31>")
	)
	(segment
		(start 32.666178 -280.04262)
		(end 32.666178 -279.890982)
		(width 0.20066)
		(layer "F.Cu")
		(net "M_C_CPU1_SA_DQ<31>")
	)
	(segment
		(start 29.661866 -280.191718)
		(end 29.899864 -280.191718)
		(width 0.101854)
		(layer "F.Cu")
		(net "M_C_CPU1_SA_DQ<31>")
	)
	(segment
		(start 33.848294 -279.974294)
		(end 34.055812 -279.766776)
		(width 0.20066)
		(layer "F.Cu")
		(net "M_C_CPU1_SA_DQ<31>")
	)
	(segment
		(start 33.401762 -279.974294)
		(end 33.848294 -279.974294)
		(width 0.20066)
		(layer "F.Cu")
		(net "M_C_CPU1_SA_DQ<31>")
	)
	(segment
		(start 32.51708 -280.191718)
		(end 32.666178 -280.04262)
		(width 0.20066)
		(layer "F.Cu")
		(net "M_C_CPU1_SA_DQ<31>")
	)
	(segment
		(start 29.29382 -280.205942)
		(end 29.647642 -280.205942)
		(width 0.20066)
		(layer "F.Cu")
		(net "M_C_CPU1_SA_DQ<31>")
	)
	(segment
		(start 35.976814 -279.766776)
		(end 34.871914 -279.766776)
		(width 0.20066)
		(layer "F.Cu")
		(net "M_C_CPU1_SA_DQ<31>")
	)
	(segment
		(start 96.713294 -263.150604)
		(end 96.713294 -263.68629)
		(width 0.20066)
		(layer "F.Cu")
		(net "M_C_CPU1_SA_DQ<31>")
	)
	(segment
		(start 31.972758 -280.191718)
		(end 32.51708 -280.191718)
		(width 0.20066)
		(layer "F.Cu")
		(net "M_C_CPU1_SA_DQ<31>")
	)
	(segment
		(start 29.025342 -279.766776)
		(end 29.151326 -279.89276)
		(width 0.20066)
		(layer "F.Cu")
		(net "M_C_CPU1_SA_DQ<31>")
	)
	(segment
		(start 32.794702 -279.762458)
		(end 33.189926 -279.762458)
		(width 0.20066)
		(layer "F.Cu")
		(net "M_C_CPU1_SA_DQ<31>")
	)
	(segment
		(start 27.328114 -279.766776)
		(end 29.025342 -279.766776)
		(width 0.20066)
		(layer "F.Cu")
		(net "M_C_CPU1_SA_DQ<31>")
	)
	(segment
		(start 29.899864 -280.191718)
		(end 31.972758 -280.191718)
		(width 0.1016)
		(layer "F.Cu")
		(net "M_C_CPU1_SA_DQ<31>")
	)
	(segment
		(start 96.713294 -263.68629)
		(end 96.713548 -263.686544)
		(width 0.20066)
		(layer "F.Cu")
		(net "M_C_CPU1_SA_DQ<31>")
	)
	(segment
		(start 32.666178 -279.890982)
		(end 32.794702 -279.762458)
		(width 0.20066)
		(layer "F.Cu")
		(net "M_C_CPU1_SA_DQ<31>")
	)
	(segment
		(start 91.731846 -263.196832)
		(end 91.726004 -263.200388)
		(width 0.088646)
		(layer "In6.Cu")
		(net "M_C_CPU1_SA_DQ<31>")
	)
	(segment
		(start 38.015418 -278.686514)
		(end 37.832538 -278.503634)
		(width 0.18288)
		(layer "In6.Cu")
		(net "M_C_CPU1_SA_DQ<31>")
	)
	(segment
		(start 95.491046 -263.196832)
		(end 95.485204 -263.200388)
		(width 0.088646)
		(layer "In6.Cu")
		(net "M_C_CPU1_SA_DQ<31>")
	)
	(segment
		(start 48.271176 -276.286722)
		(end 47.925482 -276.286722)
		(width 0.18288)
		(layer "In6.Cu")
		(net "M_C_CPU1_SA_DQ<31>")
	)
	(segment
		(start 54.991254 -273.388582)
		(end 53.568854 -273.388582)
		(width 0.18288)
		(layer "In6.Cu")
		(net "M_C_CPU1_SA_DQ<31>")
	)
	(segment
		(start 36.450778 -279.292812)
		(end 35.976814 -279.766776)
		(width 0.18288)
		(layer "In6.Cu")
		(net "M_C_CPU1_SA_DQ<31>")
	)
	(segment
		(start 40.980106 -278.437086)
		(end 40.12438 -279.292812)
		(width 0.18288)
		(layer "In6.Cu")
		(net "M_C_CPU1_SA_DQ<31>")
	)
	(segment
		(start 42.844212 -277.141432)
		(end 42.844212 -278.038306)
		(width 0.18288)
		(layer "In6.Cu")
		(net "M_C_CPU1_SA_DQ<31>")
	)
	(segment
		(start 60.392818 -272.544032)
		(end 57.749948 -272.544032)
		(width 0.18288)
		(layer "In6.Cu")
		(net "M_C_CPU1_SA_DQ<31>")
	)
	(segment
		(start 50.866294 -275.091398)
		(end 50.10912 -275.091398)
		(width 0.18288)
		(layer "In6.Cu")
		(net "M_C_CPU1_SA_DQ<31>")
	)
	(segment
		(start 39.214298 -278.503634)
		(end 38.889178 -278.503634)
		(width 0.18288)
		(layer "In6.Cu")
		(net "M_C_CPU1_SA_DQ<31>")
	)
	(segment
		(start 37.324538 -278.686514)
		(end 37.324538 -279.109932)
		(width 0.18288)
		(layer "In6.Cu")
		(net "M_C_CPU1_SA_DQ<31>")
	)
	(segment
		(start 61.083698 -272.242026)
		(end 60.694824 -272.242026)
		(width 0.18288)
		(layer "In6.Cu")
		(net "M_C_CPU1_SA_DQ<31>")
	)
	(segment
		(start 51.34483 -275.091398)
		(end 51.344576 -275.091652)
		(width 0.18288)
		(layer "In6.Cu")
		(net "M_C_CPU1_SA_DQ<31>")
	)
	(segment
		(start 57.567068 -273.248374)
		(end 57.384188 -273.431254)
		(width 0.18288)
		(layer "In6.Cu")
		(net "M_C_CPU1_SA_DQ<31>")
	)
	(segment
		(start 38.889178 -278.503634)
		(end 38.706298 -278.686514)
		(width 0.18288)
		(layer "In6.Cu")
		(net "M_C_CPU1_SA_DQ<31>")
	)
	(segment
		(start 81.944718 -264.7188)
		(end 78.763622 -266.036298)
		(width 0.18288)
		(layer "In6.Cu")
		(net "M_C_CPU1_SA_DQ<31>")
	)
	(segment
		(start 96.40062 -263.686544)
		(end 96.334834 -263.620758)
		(width 0.088646)
		(layer "In6.Cu")
		(net "M_C_CPU1_SA_DQ<31>")
	)
	(segment
		(start 38.015418 -279.109932)
		(end 38.015418 -278.686514)
		(width 0.18288)
		(layer "In6.Cu")
		(net "M_C_CPU1_SA_DQ<31>")
	)
	(segment
		(start 83.039204 -264.7188)
		(end 81.944718 -264.7188)
		(width 0.18288)
		(layer "In6.Cu")
		(net "M_C_CPU1_SA_DQ<31>")
	)
	(segment
		(start 84.005166 -263.568688)
		(end 84.005166 -264.01903)
		(width 0.088646)
		(layer "In6.Cu")
		(net "M_C_CPU1_SA_DQ<31>")
	)
	(segment
		(start 50.866548 -275.091652)
		(end 50.866294 -275.091398)
		(width 0.18288)
		(layer "In6.Cu")
		(net "M_C_CPU1_SA_DQ<31>")
	)
	(segment
		(start 57.059068 -273.431254)
		(end 56.876188 -273.248374)
		(width 0.18288)
		(layer "In6.Cu")
		(net "M_C_CPU1_SA_DQ<31>")
	)
	(segment
		(start 63.408814 -271.835626)
		(end 62.700408 -272.544032)
		(width 0.18288)
		(layer "In6.Cu")
		(net "M_C_CPU1_SA_DQ<31>")
	)
	(segment
		(start 57.567068 -272.726912)
		(end 57.567068 -273.248374)
		(width 0.18288)
		(layer "In6.Cu")
		(net "M_C_CPU1_SA_DQ<31>")
	)
	(segment
		(start 47.580296 -275.941536)
		(end 44.044108 -275.941536)
		(width 0.18288)
		(layer "In6.Cu")
		(net "M_C_CPU1_SA_DQ<31>")
	)
	(segment
		(start 37.832538 -278.503634)
		(end 37.507418 -278.503634)
		(width 0.18288)
		(layer "In6.Cu")
		(net "M_C_CPU1_SA_DQ<31>")
	)
	(segment
		(start 69.183758 -267.834364)
		(end 66.187066 -270.831056)
		(width 0.18288)
		(layer "In6.Cu")
		(net "M_C_CPU1_SA_DQ<31>")
	)
	(segment
		(start 84.242402 -263.331452)
		(end 84.005166 -263.568688)
		(width 0.088646)
		(layer "In6.Cu")
		(net "M_C_CPU1_SA_DQ<31>")
	)
	(segment
		(start 38.198298 -279.292812)
		(end 38.015418 -279.109932)
		(width 0.18288)
		(layer "In6.Cu")
		(net "M_C_CPU1_SA_DQ<31>")
	)
	(segment
		(start 37.507418 -278.503634)
		(end 37.324538 -278.686514)
		(width 0.18288)
		(layer "In6.Cu")
		(net "M_C_CPU1_SA_DQ<31>")
	)
	(segment
		(start 57.384188 -273.431254)
		(end 57.059068 -273.431254)
		(width 0.18288)
		(layer "In6.Cu")
		(net "M_C_CPU1_SA_DQ<31>")
	)
	(segment
		(start 73.523602 -266.036298)
		(end 69.183758 -267.834364)
		(width 0.18288)
		(layer "In6.Cu")
		(net "M_C_CPU1_SA_DQ<31>")
	)
	(segment
		(start 94.551246 -263.196832)
		(end 94.545404 -263.200388)
		(width 0.088646)
		(layer "In6.Cu")
		(net "M_C_CPU1_SA_DQ<31>")
	)
	(segment
		(start 47.925482 -276.286722)
		(end 47.580296 -275.941536)
		(width 0.18288)
		(layer "In6.Cu")
		(net "M_C_CPU1_SA_DQ<31>")
	)
	(segment
		(start 51.866038 -275.091398)
		(end 51.34483 -275.091398)
		(width 0.18288)
		(layer "In6.Cu")
		(net "M_C_CPU1_SA_DQ<31>")
	)
	(segment
		(start 95.496888 -263.19353)
		(end 95.491046 -263.196832)
		(width 0.088646)
		(layer "In6.Cu")
		(net "M_C_CPU1_SA_DQ<31>")
	)
	(segment
		(start 89.855802 -263.1948)
		(end 89.852246 -263.196832)
		(width 0.088646)
		(layer "In6.Cu")
		(net "M_C_CPU1_SA_DQ<31>")
	)
	(segment
		(start 65.743836 -270.831056)
		(end 64.739266 -271.835626)
		(width 0.18288)
		(layer "In6.Cu")
		(net "M_C_CPU1_SA_DQ<31>")
	)
	(segment
		(start 48.616362 -275.941536)
		(end 48.271176 -276.286722)
		(width 0.18288)
		(layer "In6.Cu")
		(net "M_C_CPU1_SA_DQ<31>")
	)
	(segment
		(start 66.187066 -270.831056)
		(end 65.743836 -270.831056)
		(width 0.18288)
		(layer "In6.Cu")
		(net "M_C_CPU1_SA_DQ<31>")
	)
	(segment
		(start 57.749948 -272.544032)
		(end 57.567068 -272.726912)
		(width 0.18288)
		(layer "In6.Cu")
		(net "M_C_CPU1_SA_DQ<31>")
	)
	(segment
		(start 62.700408 -272.544032)
		(end 61.385704 -272.544032)
		(width 0.18288)
		(layer "In6.Cu")
		(net "M_C_CPU1_SA_DQ<31>")
	)
	(segment
		(start 90.792046 -263.196832)
		(end 90.786204 -263.200388)
		(width 0.088646)
		(layer "In6.Cu")
		(net "M_C_CPU1_SA_DQ<31>")
	)
	(segment
		(start 44.044108 -275.941536)
		(end 42.844212 -277.141432)
		(width 0.18288)
		(layer "In6.Cu")
		(net "M_C_CPU1_SA_DQ<31>")
	)
	(segment
		(start 83.305396 -264.7188)
		(end 83.039204 -264.7188)
		(width 0.088646)
		(layer "In6.Cu")
		(net "M_C_CPU1_SA_DQ<31>")
	)
	(segment
		(start 88.537796 -263.197086)
		(end 88.537796 -263.196832)
		(width 0.088646)
		(layer "In6.Cu")
		(net "M_C_CPU1_SA_DQ<31>")
	)
	(segment
		(start 53.568854 -273.388582)
		(end 51.866038 -275.091398)
		(width 0.18288)
		(layer "In6.Cu")
		(net "M_C_CPU1_SA_DQ<31>")
	)
	(segment
		(start 92.671646 -263.196832)
		(end 92.665804 -263.200388)
		(width 0.088646)
		(layer "In6.Cu")
		(net "M_C_CPU1_SA_DQ<31>")
	)
	(segment
		(start 93.611446 -263.196832)
		(end 93.605604 -263.200388)
		(width 0.088646)
		(layer "In6.Cu")
		(net "M_C_CPU1_SA_DQ<31>")
	)
	(segment
		(start 88.917018 -263.194292)
		(end 88.912446 -263.196832)
		(width 0.088646)
		(layer "In6.Cu")
		(net "M_C_CPU1_SA_DQ<31>")
	)
	(segment
		(start 78.763622 -266.036298)
		(end 73.523602 -266.036298)
		(width 0.18288)
		(layer "In6.Cu")
		(net "M_C_CPU1_SA_DQ<31>")
	)
	(segment
		(start 60.694824 -272.242026)
		(end 60.392818 -272.544032)
		(width 0.18288)
		(layer "In6.Cu")
		(net "M_C_CPU1_SA_DQ<31>")
	)
	(segment
		(start 42.844212 -278.038306)
		(end 42.445432 -278.437086)
		(width 0.18288)
		(layer "In6.Cu")
		(net "M_C_CPU1_SA_DQ<31>")
	)
	(segment
		(start 84.506562 -263.204706)
		(end 84.315808 -263.282684)
		(width 0.088646)
		(layer "In6.Cu")
		(net "M_C_CPU1_SA_DQ<31>")
	)
	(segment
		(start 94.557088 -263.19353)
		(end 94.551246 -263.196832)
		(width 0.088646)
		(layer "In6.Cu")
		(net "M_C_CPU1_SA_DQ<31>")
	)
	(segment
		(start 38.706298 -279.109932)
		(end 38.523418 -279.292812)
		(width 0.18288)
		(layer "In6.Cu")
		(net "M_C_CPU1_SA_DQ<31>")
	)
	(segment
		(start 90.797888 -263.19353)
		(end 90.792046 -263.196832)
		(width 0.088646)
		(layer "In6.Cu")
		(net "M_C_CPU1_SA_DQ<31>")
	)
	(segment
		(start 91.737688 -263.19353)
		(end 91.731846 -263.196832)
		(width 0.088646)
		(layer "In6.Cu")
		(net "M_C_CPU1_SA_DQ<31>")
	)
	(segment
		(start 55.835804 -272.544032)
		(end 54.991254 -273.388582)
		(width 0.18288)
		(layer "In6.Cu")
		(net "M_C_CPU1_SA_DQ<31>")
	)
	(segment
		(start 40.12438 -279.292812)
		(end 39.580058 -279.292812)
		(width 0.18288)
		(layer "In6.Cu")
		(net "M_C_CPU1_SA_DQ<31>")
	)
	(segment
		(start 38.523418 -279.292812)
		(end 38.198298 -279.292812)
		(width 0.18288)
		(layer "In6.Cu")
		(net "M_C_CPU1_SA_DQ<31>")
	)
	(segment
		(start 84.005166 -264.01903)
		(end 83.305396 -264.7188)
		(width 0.088646)
		(layer "In6.Cu")
		(net "M_C_CPU1_SA_DQ<31>")
	)
	(segment
		(start 39.397178 -279.109932)
		(end 39.397178 -278.686514)
		(width 0.18288)
		(layer "In6.Cu")
		(net "M_C_CPU1_SA_DQ<31>")
	)
	(segment
		(start 38.706298 -278.686514)
		(end 38.706298 -279.109932)
		(width 0.18288)
		(layer "In6.Cu")
		(net "M_C_CPU1_SA_DQ<31>")
	)
	(segment
		(start 37.324538 -279.109932)
		(end 37.141658 -279.292812)
		(width 0.18288)
		(layer "In6.Cu")
		(net "M_C_CPU1_SA_DQ<31>")
	)
	(segment
		(start 56.876188 -272.726912)
		(end 56.693308 -272.544032)
		(width 0.18288)
		(layer "In6.Cu")
		(net "M_C_CPU1_SA_DQ<31>")
	)
	(segment
		(start 51.344576 -275.091652)
		(end 50.866548 -275.091652)
		(width 0.18288)
		(layer "In6.Cu")
		(net "M_C_CPU1_SA_DQ<31>")
	)
	(segment
		(start 56.693308 -272.544032)
		(end 55.835804 -272.544032)
		(width 0.18288)
		(layer "In6.Cu")
		(net "M_C_CPU1_SA_DQ<31>")
	)
	(segment
		(start 50.10912 -275.091398)
		(end 49.258982 -275.941536)
		(width 0.18288)
		(layer "In6.Cu")
		(net "M_C_CPU1_SA_DQ<31>")
	)
	(segment
		(start 92.677488 -263.19353)
		(end 92.671646 -263.196832)
		(width 0.088646)
		(layer "In6.Cu")
		(net "M_C_CPU1_SA_DQ<31>")
	)
	(segment
		(start 61.385704 -272.544032)
		(end 61.083698 -272.242026)
		(width 0.18288)
		(layer "In6.Cu")
		(net "M_C_CPU1_SA_DQ<31>")
	)
	(segment
		(start 39.397178 -278.686514)
		(end 39.214298 -278.503634)
		(width 0.18288)
		(layer "In6.Cu")
		(net "M_C_CPU1_SA_DQ<31>")
	)
	(segment
		(start 96.713548 -263.686544)
		(end 96.40062 -263.686544)
		(width 0.088646)
		(layer "In6.Cu")
		(net "M_C_CPU1_SA_DQ<31>")
	)
	(segment
		(start 64.739266 -271.835626)
		(end 63.408814 -271.835626)
		(width 0.18288)
		(layer "In6.Cu")
		(net "M_C_CPU1_SA_DQ<31>")
	)
	(segment
		(start 56.876188 -273.248374)
		(end 56.876188 -272.726912)
		(width 0.18288)
		(layer "In6.Cu")
		(net "M_C_CPU1_SA_DQ<31>")
	)
	(segment
		(start 39.580058 -279.292812)
		(end 39.397178 -279.109932)
		(width 0.18288)
		(layer "In6.Cu")
		(net "M_C_CPU1_SA_DQ<31>")
	)
	(segment
		(start 93.617288 -263.19353)
		(end 93.611446 -263.196832)
		(width 0.088646)
		(layer "In6.Cu")
		(net "M_C_CPU1_SA_DQ<31>")
	)
	(segment
		(start 49.258982 -275.941536)
		(end 48.616362 -275.941536)
		(width 0.18288)
		(layer "In6.Cu")
		(net "M_C_CPU1_SA_DQ<31>")
	)
	(segment
		(start 42.445432 -278.437086)
		(end 40.980106 -278.437086)
		(width 0.18288)
		(layer "In6.Cu")
		(net "M_C_CPU1_SA_DQ<31>")
	)
	(segment
		(start 88.912446 -263.196832)
		(end 88.906604 -263.200388)
		(width 0.088646)
		(layer "In6.Cu")
		(net "M_C_CPU1_SA_DQ<31>")
	)
	(segment
		(start 37.141658 -279.292812)
		(end 36.450778 -279.292812)
		(width 0.18288)
		(layer "In6.Cu")
		(net "M_C_CPU1_SA_DQ<31>")
	)
	(arc
		(start 94.545404 -263.200388)
		(mid 94.360549 -263.247306)
		(end 94.176596 -263.197086)
		(width 0.088646)
		(layer "In6.Cu")
		(net "M_C_CPU1_SA_DQ<31>")
	)
	(arc
		(start 84.315808 -263.282684)
		(mid 84.276677 -263.303412)
		(end 84.242402 -263.331452)
		(width 0.088646)
		(layer "In6.Cu")
		(net "M_C_CPU1_SA_DQ<31>")
	)
	(arc
		(start 85.152992 -263.196832)
		(mid 84.981844 -263.246747)
		(end 84.807044 -263.211818)
		(width 0.088646)
		(layer "In6.Cu")
		(net "M_C_CPU1_SA_DQ<31>")
	)
	(arc
		(start 94.176596 -263.197086)
		(mid 93.897422 -263.121321)
		(end 93.617288 -263.19353)
		(width 0.088646)
		(layer "In6.Cu")
		(net "M_C_CPU1_SA_DQ<31>")
	)
	(arc
		(start 96.056196 -263.197086)
		(mid 95.777022 -263.121321)
		(end 95.496888 -263.19353)
		(width 0.088646)
		(layer "In6.Cu")
		(net "M_C_CPU1_SA_DQ<31>")
	)
	(arc
		(start 89.852246 -263.196832)
		(mid 89.664938 -263.246975)
		(end 89.477596 -263.196832)
		(width 0.088646)
		(layer "In6.Cu")
		(net "M_C_CPU1_SA_DQ<31>")
	)
	(arc
		(start 95.485204 -263.200388)
		(mid 95.300349 -263.247306)
		(end 95.116396 -263.197086)
		(width 0.088646)
		(layer "In6.Cu")
		(net "M_C_CPU1_SA_DQ<31>")
	)
	(arc
		(start 92.296996 -263.197086)
		(mid 92.017822 -263.121321)
		(end 91.737688 -263.19353)
		(width 0.088646)
		(layer "In6.Cu")
		(net "M_C_CPU1_SA_DQ<31>")
	)
	(arc
		(start 95.116396 -263.197086)
		(mid 94.837222 -263.121321)
		(end 94.557088 -263.19353)
		(width 0.088646)
		(layer "In6.Cu")
		(net "M_C_CPU1_SA_DQ<31>")
	)
	(arc
		(start 90.417396 -263.197086)
		(mid 90.136915 -263.121314)
		(end 89.855802 -263.1948)
		(width 0.088646)
		(layer "In6.Cu")
		(net "M_C_CPU1_SA_DQ<31>")
	)
	(arc
		(start 85.718396 -263.196832)
		(mid 85.435694 -263.12109)
		(end 85.152992 -263.196832)
		(width 0.088646)
		(layer "In6.Cu")
		(net "M_C_CPU1_SA_DQ<31>")
	)
	(arc
		(start 87.032592 -263.196832)
		(mid 86.845394 -263.246975)
		(end 86.658196 -263.196832)
		(width 0.088646)
		(layer "In6.Cu")
		(net "M_C_CPU1_SA_DQ<31>")
	)
	(arc
		(start 88.906604 -263.200388)
		(mid 88.721749 -263.247306)
		(end 88.537796 -263.197086)
		(width 0.088646)
		(layer "In6.Cu")
		(net "M_C_CPU1_SA_DQ<31>")
	)
	(arc
		(start 88.537796 -263.196832)
		(mid 88.255094 -263.12109)
		(end 87.972392 -263.196832)
		(width 0.088646)
		(layer "In6.Cu")
		(net "M_C_CPU1_SA_DQ<31>")
	)
	(arc
		(start 92.665804 -263.200388)
		(mid 92.480949 -263.247306)
		(end 92.296996 -263.197086)
		(width 0.088646)
		(layer "In6.Cu")
		(net "M_C_CPU1_SA_DQ<31>")
	)
	(arc
		(start 86.658196 -263.196832)
		(mid 86.375494 -263.12109)
		(end 86.092792 -263.196832)
		(width 0.088646)
		(layer "In6.Cu")
		(net "M_C_CPU1_SA_DQ<31>")
	)
	(arc
		(start 91.357196 -263.197086)
		(mid 91.078022 -263.121321)
		(end 90.797888 -263.19353)
		(width 0.088646)
		(layer "In6.Cu")
		(net "M_C_CPU1_SA_DQ<31>")
	)
	(arc
		(start 90.786204 -263.200388)
		(mid 90.601349 -263.247306)
		(end 90.417396 -263.197086)
		(width 0.088646)
		(layer "In6.Cu")
		(net "M_C_CPU1_SA_DQ<31>")
	)
	(arc
		(start 93.605604 -263.200388)
		(mid 93.420749 -263.247306)
		(end 93.236796 -263.197086)
		(width 0.088646)
		(layer "In6.Cu")
		(net "M_C_CPU1_SA_DQ<31>")
	)
	(arc
		(start 86.092792 -263.196832)
		(mid 85.905594 -263.246975)
		(end 85.718396 -263.196832)
		(width 0.088646)
		(layer "In6.Cu")
		(net "M_C_CPU1_SA_DQ<31>")
	)
	(arc
		(start 91.726004 -263.200388)
		(mid 91.541149 -263.247306)
		(end 91.357196 -263.197086)
		(width 0.088646)
		(layer "In6.Cu")
		(net "M_C_CPU1_SA_DQ<31>")
	)
	(arc
		(start 87.597996 -263.196832)
		(mid 87.315294 -263.12109)
		(end 87.032592 -263.196832)
		(width 0.088646)
		(layer "In6.Cu")
		(net "M_C_CPU1_SA_DQ<31>")
	)
	(arc
		(start 93.236796 -263.197086)
		(mid 92.957622 -263.121321)
		(end 92.677488 -263.19353)
		(width 0.088646)
		(layer "In6.Cu")
		(net "M_C_CPU1_SA_DQ<31>")
	)
	(arc
		(start 89.477596 -263.196832)
		(mid 89.197652 -263.121188)
		(end 88.917018 -263.194292)
		(width 0.088646)
		(layer "In6.Cu")
		(net "M_C_CPU1_SA_DQ<31>")
	)
	(arc
		(start 84.807044 -263.211818)
		(mid 84.657557 -263.176815)
		(end 84.506562 -263.204706)
		(width 0.088646)
		(layer "In6.Cu")
		(net "M_C_CPU1_SA_DQ<31>")
	)
	(arc
		(start 96.334834 -263.620758)
		(mid 96.245676 -263.37594)
		(end 96.056196 -263.197086)
		(width 0.088646)
		(layer "In6.Cu")
		(net "M_C_CPU1_SA_DQ<31>")
	)
	(arc
		(start 87.972392 -263.196832)
		(mid 87.785194 -263.246975)
		(end 87.597996 -263.196832)
		(width 0.088646)
		(layer "In6.Cu")
		(net "M_C_CPU1_SA_DQ<31>")
	)
	(segment
		(start 28.91028 -281.031696)
		(end 29.647642 -281.031696)
		(width 0.20066)
		(layer "F.Cu")
		(net "M_C_CPU1_SA_DQ<30>")
	)
	(segment
		(start 29.647642 -281.031696)
		(end 29.657802 -281.041856)
		(width 0.101854)
		(layer "F.Cu")
		(net "M_C_CPU1_SA_DQ<30>")
	)
	(segment
		(start 29.912818 -281.041856)
		(end 31.972758 -281.041856)
		(width 0.1016)
		(layer "F.Cu")
		(net "M_C_CPU1_SA_DQ<30>")
	)
	(segment
		(start 32.605726 -281.041856)
		(end 32.74949 -281.18562)
		(width 0.20066)
		(layer "F.Cu")
		(net "M_C_CPU1_SA_DQ<30>")
	)
	(segment
		(start 27.328114 -281.466798)
		(end 28.475178 -281.466798)
		(width 0.20066)
		(layer "F.Cu")
		(net "M_C_CPU1_SA_DQ<30>")
	)
	(segment
		(start 33.55721 -281.466798)
		(end 34.871914 -281.466798)
		(width 0.20066)
		(layer "F.Cu")
		(net "M_C_CPU1_SA_DQ<30>")
	)
	(segment
		(start 28.475178 -281.466798)
		(end 28.91028 -281.031696)
		(width 0.20066)
		(layer "F.Cu")
		(net "M_C_CPU1_SA_DQ<30>")
	)
	(segment
		(start 97.183448 -263.96442)
		(end 97.183194 -263.964674)
		(width 0.20066)
		(layer "F.Cu")
		(net "M_C_CPU1_SA_DQ<30>")
	)
	(segment
		(start 32.916876 -281.678634)
		(end 33.345374 -281.678634)
		(width 0.20066)
		(layer "F.Cu")
		(net "M_C_CPU1_SA_DQ<30>")
	)
	(segment
		(start 35.976814 -281.466798)
		(end 34.871914 -281.466798)
		(width 0.20066)
		(layer "F.Cu")
		(net "M_C_CPU1_SA_DQ<30>")
	)
	(segment
		(start 32.74949 -281.511248)
		(end 32.916876 -281.678634)
		(width 0.20066)
		(layer "F.Cu")
		(net "M_C_CPU1_SA_DQ<30>")
	)
	(segment
		(start 31.972758 -281.041856)
		(end 32.605726 -281.041856)
		(width 0.20066)
		(layer "F.Cu")
		(net "M_C_CPU1_SA_DQ<30>")
	)
	(segment
		(start 33.345374 -281.678634)
		(end 33.55721 -281.466798)
		(width 0.20066)
		(layer "F.Cu")
		(net "M_C_CPU1_SA_DQ<30>")
	)
	(segment
		(start 32.74949 -281.18562)
		(end 32.74949 -281.511248)
		(width 0.20066)
		(layer "F.Cu")
		(net "M_C_CPU1_SA_DQ<30>")
	)
	(segment
		(start 97.183194 -263.964674)
		(end 97.183194 -264.50036)
		(width 0.20066)
		(layer "F.Cu")
		(net "M_C_CPU1_SA_DQ<30>")
	)
	(segment
		(start 29.657802 -281.041856)
		(end 29.912818 -281.041856)
		(width 0.101854)
		(layer "F.Cu")
		(net "M_C_CPU1_SA_DQ<30>")
	)
	(segment
		(start 66.481706 -272.503646)
		(end 65.86982 -272.503646)
		(width 0.18288)
		(layer "In6.Cu")
		(net "M_C_CPU1_SA_DQ<30>")
	)
	(segment
		(start 83.589876 -265.81227)
		(end 83.039204 -265.81227)
		(width 0.088646)
		(layer "In6.Cu")
		(net "M_C_CPU1_SA_DQ<30>")
	)
	(segment
		(start 37.991034 -281.835098)
		(end 37.752274 -281.736038)
		(width 0.18288)
		(layer "In6.Cu")
		(net "M_C_CPU1_SA_DQ<30>")
	)
	(segment
		(start 92.216478 -264.002266)
		(end 92.201746 -264.010902)
		(width 0.088646)
		(layer "In6.Cu")
		(net "M_C_CPU1_SA_DQ<30>")
	)
	(segment
		(start 52.68214 -276.79142)
		(end 50.01133 -276.79142)
		(width 0.18288)
		(layer "In6.Cu")
		(net "M_C_CPU1_SA_DQ<30>")
	)
	(segment
		(start 37.752274 -281.736038)
		(end 37.049202 -282.027376)
		(width 0.18288)
		(layer "In6.Cu")
		(net "M_C_CPU1_SA_DQ<30>")
	)
	(segment
		(start 90.332306 -264.004806)
		(end 90.321892 -264.010902)
		(width 0.088646)
		(layer "In6.Cu")
		(net "M_C_CPU1_SA_DQ<30>")
	)
	(segment
		(start 53.467508 -275.361908)
		(end 53.208936 -275.361908)
		(width 0.18288)
		(layer "In6.Cu")
		(net "M_C_CPU1_SA_DQ<30>")
	)
	(segment
		(start 53.171598 -276.301962)
		(end 52.68214 -276.79142)
		(width 0.18288)
		(layer "In6.Cu")
		(net "M_C_CPU1_SA_DQ<30>")
	)
	(segment
		(start 48.082962 -277.993856)
		(end 47.74438 -277.993856)
		(width 0.18288)
		(layer "In6.Cu")
		(net "M_C_CPU1_SA_DQ<30>")
	)
	(segment
		(start 84.307934 -264.690606)
		(end 83.891882 -265.106658)
		(width 0.088646)
		(layer "In6.Cu")
		(net "M_C_CPU1_SA_DQ<30>")
	)
	(segment
		(start 64.695832 -273.419062)
		(end 64.4652 -273.18843)
		(width 0.18288)
		(layer "In6.Cu")
		(net "M_C_CPU1_SA_DQ<30>")
	)
	(segment
		(start 47.392082 -277.641558)
		(end 46.259242 -277.641558)
		(width 0.18288)
		(layer "In6.Cu")
		(net "M_C_CPU1_SA_DQ<30>")
	)
	(segment
		(start 36.537392 -282.027376)
		(end 35.976814 -281.466798)
		(width 0.18288)
		(layer "In6.Cu")
		(net "M_C_CPU1_SA_DQ<30>")
	)
	(segment
		(start 46.259242 -277.641558)
		(end 45.383958 -278.516842)
		(width 0.18288)
		(layer "In6.Cu")
		(net "M_C_CPU1_SA_DQ<30>")
	)
	(segment
		(start 60.29325 -274.260564)
		(end 60.11037 -274.443444)
		(width 0.18288)
		(layer "In6.Cu")
		(net "M_C_CPU1_SA_DQ<30>")
	)
	(segment
		(start 45.383958 -278.516842)
		(end 44.560998 -278.516842)
		(width 0.18288)
		(layer "In6.Cu")
		(net "M_C_CPU1_SA_DQ<30>")
	)
	(segment
		(start 60.98413 -273.945858)
		(end 60.80125 -273.762978)
		(width 0.18288)
		(layer "In6.Cu")
		(net "M_C_CPU1_SA_DQ<30>")
	)
	(segment
		(start 49.161192 -277.641558)
		(end 48.43526 -277.641558)
		(width 0.18288)
		(layer "In6.Cu")
		(net "M_C_CPU1_SA_DQ<30>")
	)
	(segment
		(start 38.600634 -281.978608)
		(end 38.300152 -282.103322)
		(width 0.18288)
		(layer "In6.Cu")
		(net "M_C_CPU1_SA_DQ<30>")
	)
	(segment
		(start 54.172358 -275.301202)
		(end 53.918866 -275.554694)
		(width 0.18288)
		(layer "In6.Cu")
		(net "M_C_CPU1_SA_DQ<30>")
	)
	(segment
		(start 38.300152 -282.103322)
		(end 38.061392 -282.004262)
		(width 0.18288)
		(layer "In6.Cu")
		(net "M_C_CPU1_SA_DQ<30>")
	)
	(segment
		(start 60.80125 -273.762978)
		(end 60.47613 -273.762978)
		(width 0.18288)
		(layer "In6.Cu")
		(net "M_C_CPU1_SA_DQ<30>")
	)
	(segment
		(start 83.891882 -265.106658)
		(end 83.891882 -265.510264)
		(width 0.088646)
		(layer "In6.Cu")
		(net "M_C_CPU1_SA_DQ<30>")
	)
	(segment
		(start 47.74438 -277.993856)
		(end 47.392082 -277.641558)
		(width 0.18288)
		(layer "In6.Cu")
		(net "M_C_CPU1_SA_DQ<30>")
	)
	(segment
		(start 43.077384 -279.531826)
		(end 42.473372 -280.135838)
		(width 0.18288)
		(layer "In6.Cu")
		(net "M_C_CPU1_SA_DQ<30>")
	)
	(segment
		(start 64.4652 -273.18843)
		(end 64.206628 -273.18843)
		(width 0.18288)
		(layer "In6.Cu")
		(net "M_C_CPU1_SA_DQ<30>")
	)
	(segment
		(start 60.47613 -273.762978)
		(end 60.29325 -273.945858)
		(width 0.18288)
		(layer "In6.Cu")
		(net "M_C_CPU1_SA_DQ<30>")
	)
	(segment
		(start 95.597218 -264.017252)
		(end 95.571564 -264.002266)
		(width 0.088646)
		(layer "In6.Cu")
		(net "M_C_CPU1_SA_DQ<30>")
	)
	(segment
		(start 55.579264 -274.443444)
		(end 54.721506 -275.301202)
		(width 0.18288)
		(layer "In6.Cu")
		(net "M_C_CPU1_SA_DQ<30>")
	)
	(segment
		(start 37.049202 -282.027376)
		(end 36.537392 -282.027376)
		(width 0.18288)
		(layer "In6.Cu")
		(net "M_C_CPU1_SA_DQ<30>")
	)
	(segment
		(start 94.09176 -264.004806)
		(end 94.081346 -264.010902)
		(width 0.088646)
		(layer "In6.Cu")
		(net "M_C_CPU1_SA_DQ<30>")
	)
	(segment
		(start 60.29325 -273.945858)
		(end 60.29325 -274.260564)
		(width 0.18288)
		(layer "In6.Cu")
		(net "M_C_CPU1_SA_DQ<30>")
	)
	(segment
		(start 38.629336 -281.57043)
		(end 38.699694 -281.739848)
		(width 0.18288)
		(layer "In6.Cu")
		(net "M_C_CPU1_SA_DQ<30>")
	)
	(segment
		(start 63.976504 -273.677126)
		(end 64.207136 -273.907758)
		(width 0.18288)
		(layer "In6.Cu")
		(net "M_C_CPU1_SA_DQ<30>")
	)
	(segment
		(start 64.206628 -273.18843)
		(end 63.976504 -273.418554)
		(width 0.18288)
		(layer "In6.Cu")
		(net "M_C_CPU1_SA_DQ<30>")
	)
	(segment
		(start 44.560998 -278.516842)
		(end 43.546014 -279.531826)
		(width 0.18288)
		(layer "In6.Cu")
		(net "M_C_CPU1_SA_DQ<30>")
	)
	(segment
		(start 81.95183 -265.81227)
		(end 78.93812 -267.060426)
		(width 0.18288)
		(layer "In6.Cu")
		(net "M_C_CPU1_SA_DQ<30>")
	)
	(segment
		(start 64.207136 -274.16633)
		(end 63.930022 -274.443444)
		(width 0.18288)
		(layer "In6.Cu")
		(net "M_C_CPU1_SA_DQ<30>")
	)
	(segment
		(start 83.891882 -265.510264)
		(end 83.589876 -265.81227)
		(width 0.088646)
		(layer "In6.Cu")
		(net "M_C_CPU1_SA_DQ<30>")
	)
	(segment
		(start 60.11037 -274.443444)
		(end 55.579264 -274.443444)
		(width 0.18288)
		(layer "In6.Cu")
		(net "M_C_CPU1_SA_DQ<30>")
	)
	(segment
		(start 93.156278 -264.002266)
		(end 93.141546 -264.010902)
		(width 0.088646)
		(layer "In6.Cu")
		(net "M_C_CPU1_SA_DQ<30>")
	)
	(segment
		(start 38.699694 -281.739848)
		(end 38.600634 -281.978608)
		(width 0.18288)
		(layer "In6.Cu")
		(net "M_C_CPU1_SA_DQ<30>")
	)
	(segment
		(start 39.35476 -280.852626)
		(end 38.979602 -281.227784)
		(width 0.18288)
		(layer "In6.Cu")
		(net "M_C_CPU1_SA_DQ<30>")
	)
	(segment
		(start 38.979602 -281.227784)
		(end 38.728396 -281.331924)
		(width 0.18288)
		(layer "In6.Cu")
		(net "M_C_CPU1_SA_DQ<30>")
	)
	(segment
		(start 54.721506 -275.301202)
		(end 54.172358 -275.301202)
		(width 0.18288)
		(layer "In6.Cu")
		(net "M_C_CPU1_SA_DQ<30>")
	)
	(segment
		(start 52.978812 -275.592032)
		(end 52.978812 -275.850604)
		(width 0.18288)
		(layer "In6.Cu")
		(net "M_C_CPU1_SA_DQ<30>")
	)
	(segment
		(start 52.978812 -275.850604)
		(end 53.171598 -276.04339)
		(width 0.18288)
		(layer "In6.Cu")
		(net "M_C_CPU1_SA_DQ<30>")
	)
	(segment
		(start 42.473372 -280.135838)
		(end 40.926766 -280.135838)
		(width 0.18288)
		(layer "In6.Cu")
		(net "M_C_CPU1_SA_DQ<30>")
	)
	(segment
		(start 40.926766 -280.135838)
		(end 40.209978 -280.852626)
		(width 0.18288)
		(layer "In6.Cu")
		(net "M_C_CPU1_SA_DQ<30>")
	)
	(segment
		(start 65.86982 -272.503646)
		(end 64.954404 -273.419062)
		(width 0.18288)
		(layer "In6.Cu")
		(net "M_C_CPU1_SA_DQ<30>")
	)
	(segment
		(start 64.954404 -273.419062)
		(end 64.695832 -273.419062)
		(width 0.18288)
		(layer "In6.Cu")
		(net "M_C_CPU1_SA_DQ<30>")
	)
	(segment
		(start 61.16701 -274.443444)
		(end 60.98413 -274.260564)
		(width 0.18288)
		(layer "In6.Cu")
		(net "M_C_CPU1_SA_DQ<30>")
	)
	(segment
		(start 63.930022 -274.443444)
		(end 61.16701 -274.443444)
		(width 0.18288)
		(layer "In6.Cu")
		(net "M_C_CPU1_SA_DQ<30>")
	)
	(segment
		(start 50.01133 -276.79142)
		(end 49.161192 -277.641558)
		(width 0.18288)
		(layer "In6.Cu")
		(net "M_C_CPU1_SA_DQ<30>")
	)
	(segment
		(start 83.039204 -265.81227)
		(end 81.95183 -265.81227)
		(width 0.18288)
		(layer "In6.Cu")
		(net "M_C_CPU1_SA_DQ<30>")
	)
	(segment
		(start 64.207136 -273.907758)
		(end 64.207136 -274.16633)
		(width 0.18288)
		(layer "In6.Cu")
		(net "M_C_CPU1_SA_DQ<30>")
	)
	(segment
		(start 38.728396 -281.331924)
		(end 38.629336 -281.57043)
		(width 0.18288)
		(layer "In6.Cu")
		(net "M_C_CPU1_SA_DQ<30>")
	)
	(segment
		(start 53.171598 -276.04339)
		(end 53.171598 -276.301962)
		(width 0.18288)
		(layer "In6.Cu")
		(net "M_C_CPU1_SA_DQ<30>")
	)
	(segment
		(start 96.624902 -264.068814)
		(end 96.541844 -264.020046)
		(width 0.088646)
		(layer "In6.Cu")
		(net "M_C_CPU1_SA_DQ<30>")
	)
	(segment
		(start 84.307934 -264.358628)
		(end 84.307934 -264.690606)
		(width 0.088646)
		(layer "In6.Cu")
		(net "M_C_CPU1_SA_DQ<30>")
	)
	(segment
		(start 78.93812 -267.060426)
		(end 73.907904 -267.060426)
		(width 0.18288)
		(layer "In6.Cu")
		(net "M_C_CPU1_SA_DQ<30>")
	)
	(segment
		(start 40.209978 -280.852626)
		(end 39.35476 -280.852626)
		(width 0.18288)
		(layer "In6.Cu")
		(net "M_C_CPU1_SA_DQ<30>")
	)
	(segment
		(start 43.546014 -279.531826)
		(end 43.077384 -279.531826)
		(width 0.18288)
		(layer "In6.Cu")
		(net "M_C_CPU1_SA_DQ<30>")
	)
	(segment
		(start 84.565998 -264.100564)
		(end 84.307934 -264.358628)
		(width 0.088646)
		(layer "In6.Cu")
		(net "M_C_CPU1_SA_DQ<30>")
	)
	(segment
		(start 53.208936 -275.361908)
		(end 52.978812 -275.592032)
		(width 0.18288)
		(layer "In6.Cu")
		(net "M_C_CPU1_SA_DQ<30>")
	)
	(segment
		(start 53.918866 -275.554694)
		(end 53.660294 -275.554694)
		(width 0.18288)
		(layer "In6.Cu")
		(net "M_C_CPU1_SA_DQ<30>")
	)
	(segment
		(start 63.976504 -273.418554)
		(end 63.976504 -273.677126)
		(width 0.18288)
		(layer "In6.Cu")
		(net "M_C_CPU1_SA_DQ<30>")
	)
	(segment
		(start 60.98413 -274.260564)
		(end 60.98413 -273.945858)
		(width 0.18288)
		(layer "In6.Cu")
		(net "M_C_CPU1_SA_DQ<30>")
	)
	(segment
		(start 48.43526 -277.641558)
		(end 48.082962 -277.993856)
		(width 0.18288)
		(layer "In6.Cu")
		(net "M_C_CPU1_SA_DQ<30>")
	)
	(segment
		(start 53.660294 -275.554694)
		(end 53.467508 -275.361908)
		(width 0.18288)
		(layer "In6.Cu")
		(net "M_C_CPU1_SA_DQ<30>")
	)
	(segment
		(start 70.522592 -268.46276)
		(end 66.481706 -272.503646)
		(width 0.18288)
		(layer "In6.Cu")
		(net "M_C_CPU1_SA_DQ<30>")
	)
	(segment
		(start 73.907904 -267.060426)
		(end 70.522592 -268.46276)
		(width 0.18288)
		(layer "In6.Cu")
		(net "M_C_CPU1_SA_DQ<30>")
	)
	(segment
		(start 97.183194 -264.50036)
		(end 96.624902 -264.068814)
		(width 0.088646)
		(layer "In6.Cu")
		(net "M_C_CPU1_SA_DQ<30>")
	)
	(segment
		(start 38.061392 -282.004262)
		(end 37.991034 -281.835098)
		(width 0.18288)
		(layer "In6.Cu")
		(net "M_C_CPU1_SA_DQ<30>")
	)
	(arc
		(start 86.562692 -264.010902)
		(mid 86.375494 -264.061045)
		(end 86.188296 -264.010902)
		(width 0.088646)
		(layer "In6.Cu")
		(net "M_C_CPU1_SA_DQ<30>")
	)
	(arc
		(start 93.70695 -264.010902)
		(mid 93.432751 -263.935067)
		(end 93.156278 -264.002266)
		(width 0.088646)
		(layer "In6.Cu")
		(net "M_C_CPU1_SA_DQ<30>")
	)
	(arc
		(start 88.067896 -264.010902)
		(mid 87.785194 -263.935126)
		(end 87.502492 -264.010902)
		(width 0.088646)
		(layer "In6.Cu")
		(net "M_C_CPU1_SA_DQ<30>")
	)
	(arc
		(start 89.007696 -264.010902)
		(mid 88.724994 -263.935126)
		(end 88.442292 -264.010902)
		(width 0.088646)
		(layer "In6.Cu")
		(net "M_C_CPU1_SA_DQ<30>")
	)
	(arc
		(start 90.321892 -264.010902)
		(mid 90.134694 -264.061045)
		(end 89.947496 -264.010902)
		(width 0.088646)
		(layer "In6.Cu")
		(net "M_C_CPU1_SA_DQ<30>")
	)
	(arc
		(start 94.081346 -264.010902)
		(mid 93.894148 -264.061045)
		(end 93.70695 -264.010902)
		(width 0.088646)
		(layer "In6.Cu")
		(net "M_C_CPU1_SA_DQ<30>")
	)
	(arc
		(start 96.541844 -264.020046)
		(mid 96.257575 -263.942533)
		(end 95.972884 -264.018522)
		(width 0.088646)
		(layer "In6.Cu")
		(net "M_C_CPU1_SA_DQ<30>")
	)
	(arc
		(start 84.683092 -264.010902)
		(mid 84.621614 -264.051904)
		(end 84.565998 -264.100564)
		(width 0.088646)
		(layer "In6.Cu")
		(net "M_C_CPU1_SA_DQ<30>")
	)
	(arc
		(start 89.382092 -264.010902)
		(mid 89.194894 -264.061045)
		(end 89.007696 -264.010902)
		(width 0.088646)
		(layer "In6.Cu")
		(net "M_C_CPU1_SA_DQ<30>")
	)
	(arc
		(start 87.502492 -264.010902)
		(mid 87.315294 -264.061045)
		(end 87.128096 -264.010902)
		(width 0.088646)
		(layer "In6.Cu")
		(net "M_C_CPU1_SA_DQ<30>")
	)
	(arc
		(start 91.261946 -264.010902)
		(mid 91.074748 -264.061045)
		(end 90.88755 -264.010902)
		(width 0.088646)
		(layer "In6.Cu")
		(net "M_C_CPU1_SA_DQ<30>")
	)
	(arc
		(start 85.248496 -264.010902)
		(mid 84.965794 -263.935126)
		(end 84.683092 -264.010902)
		(width 0.088646)
		(layer "In6.Cu")
		(net "M_C_CPU1_SA_DQ<30>")
	)
	(arc
		(start 89.947496 -264.010902)
		(mid 89.664794 -263.935126)
		(end 89.382092 -264.010902)
		(width 0.088646)
		(layer "In6.Cu")
		(net "M_C_CPU1_SA_DQ<30>")
	)
	(arc
		(start 87.128096 -264.010902)
		(mid 86.845394 -263.935126)
		(end 86.562692 -264.010902)
		(width 0.088646)
		(layer "In6.Cu")
		(net "M_C_CPU1_SA_DQ<30>")
	)
	(arc
		(start 95.571564 -264.002266)
		(mid 95.295089 -263.934946)
		(end 95.020892 -264.010902)
		(width 0.088646)
		(layer "In6.Cu")
		(net "M_C_CPU1_SA_DQ<30>")
	)
	(arc
		(start 92.201746 -264.010902)
		(mid 92.014548 -264.061045)
		(end 91.82735 -264.010902)
		(width 0.088646)
		(layer "In6.Cu")
		(net "M_C_CPU1_SA_DQ<30>")
	)
	(arc
		(start 90.88755 -264.010902)
		(mid 90.610737 -263.935032)
		(end 90.332306 -264.004806)
		(width 0.088646)
		(layer "In6.Cu")
		(net "M_C_CPU1_SA_DQ<30>")
	)
	(arc
		(start 92.76715 -264.010902)
		(mid 92.492951 -263.935067)
		(end 92.216478 -264.002266)
		(width 0.088646)
		(layer "In6.Cu")
		(net "M_C_CPU1_SA_DQ<30>")
	)
	(arc
		(start 95.972884 -264.018522)
		(mid 95.784887 -264.068511)
		(end 95.597218 -264.017252)
		(width 0.088646)
		(layer "In6.Cu")
		(net "M_C_CPU1_SA_DQ<30>")
	)
	(arc
		(start 94.646496 -264.010902)
		(mid 94.369937 -263.935159)
		(end 94.09176 -264.004806)
		(width 0.088646)
		(layer "In6.Cu")
		(net "M_C_CPU1_SA_DQ<30>")
	)
	(arc
		(start 88.442292 -264.010902)
		(mid 88.255094 -264.061045)
		(end 88.067896 -264.010902)
		(width 0.088646)
		(layer "In6.Cu")
		(net "M_C_CPU1_SA_DQ<30>")
	)
	(arc
		(start 95.020892 -264.010902)
		(mid 94.833694 -264.061045)
		(end 94.646496 -264.010902)
		(width 0.088646)
		(layer "In6.Cu")
		(net "M_C_CPU1_SA_DQ<30>")
	)
	(arc
		(start 85.622892 -264.010902)
		(mid 85.435694 -264.061045)
		(end 85.248496 -264.010902)
		(width 0.088646)
		(layer "In6.Cu")
		(net "M_C_CPU1_SA_DQ<30>")
	)
	(arc
		(start 93.141546 -264.010902)
		(mid 92.954348 -264.061045)
		(end 92.76715 -264.010902)
		(width 0.088646)
		(layer "In6.Cu")
		(net "M_C_CPU1_SA_DQ<30>")
	)
	(arc
		(start 91.82735 -264.010902)
		(mid 91.544648 -263.935126)
		(end 91.261946 -264.010902)
		(width 0.088646)
		(layer "In6.Cu")
		(net "M_C_CPU1_SA_DQ<30>")
	)
	(arc
		(start 86.188296 -264.010902)
		(mid 85.905594 -263.935126)
		(end 85.622892 -264.010902)
		(width 0.088646)
		(layer "In6.Cu")
		(net "M_C_CPU1_SA_DQ<30>")
	)
	(segment
		(start 28.91028 -315.031628)
		(end 29.647642 -315.031628)
		(width 0.20066)
		(layer "F.Cu")
		(net "M_C_CPU1_SA_DQ<2>")
	)
	(segment
		(start 33.345374 -315.678566)
		(end 33.55721 -315.46673)
		(width 0.20066)
		(layer "F.Cu")
		(net "M_C_CPU1_SA_DQ<2>")
	)
	(segment
		(start 32.916876 -315.678566)
		(end 33.345374 -315.678566)
		(width 0.20066)
		(layer "F.Cu")
		(net "M_C_CPU1_SA_DQ<2>")
	)
	(segment
		(start 29.647642 -315.031628)
		(end 29.657802 -315.041788)
		(width 0.101854)
		(layer "F.Cu")
		(net "M_C_CPU1_SA_DQ<2>")
	)
	(segment
		(start 33.55721 -315.46673)
		(end 34.871914 -315.46673)
		(width 0.20066)
		(layer "F.Cu")
		(net "M_C_CPU1_SA_DQ<2>")
	)
	(segment
		(start 27.328114 -315.46673)
		(end 28.475178 -315.46673)
		(width 0.20066)
		(layer "F.Cu")
		(net "M_C_CPU1_SA_DQ<2>")
	)
	(segment
		(start 29.912818 -315.041788)
		(end 31.972758 -315.041788)
		(width 0.1016)
		(layer "F.Cu")
		(net "M_C_CPU1_SA_DQ<2>")
	)
	(segment
		(start 28.475178 -315.46673)
		(end 28.91028 -315.031628)
		(width 0.20066)
		(layer "F.Cu")
		(net "M_C_CPU1_SA_DQ<2>")
	)
	(segment
		(start 32.74949 -315.51118)
		(end 32.916876 -315.678566)
		(width 0.20066)
		(layer "F.Cu")
		(net "M_C_CPU1_SA_DQ<2>")
	)
	(segment
		(start 31.972758 -315.041788)
		(end 32.605726 -315.041788)
		(width 0.20066)
		(layer "F.Cu")
		(net "M_C_CPU1_SA_DQ<2>")
	)
	(segment
		(start 29.657802 -315.041788)
		(end 29.912818 -315.041788)
		(width 0.101854)
		(layer "F.Cu")
		(net "M_C_CPU1_SA_DQ<2>")
	)
	(segment
		(start 93.424248 -278.614378)
		(end 93.423994 -279.150318)
		(width 0.20066)
		(layer "F.Cu")
		(net "M_C_CPU1_SA_DQ<2>")
	)
	(segment
		(start 32.605726 -315.041788)
		(end 32.74949 -315.185552)
		(width 0.20066)
		(layer "F.Cu")
		(net "M_C_CPU1_SA_DQ<2>")
	)
	(segment
		(start 35.976814 -315.46673)
		(end 34.871914 -315.46673)
		(width 0.20066)
		(layer "F.Cu")
		(net "M_C_CPU1_SA_DQ<2>")
	)
	(segment
		(start 32.74949 -315.185552)
		(end 32.74949 -315.51118)
		(width 0.20066)
		(layer "F.Cu")
		(net "M_C_CPU1_SA_DQ<2>")
	)
	(segment
		(start 91.449144 -283.205682)
		(end 91.449144 -283.219906)
		(width 0.088646)
		(layer "In4.Cu")
		(net "M_C_CPU1_SA_DQ<2>")
	)
	(segment
		(start 92.719398 -278.74341)
		(end 92.719144 -278.74341)
		(width 0.088646)
		(layer "In4.Cu")
		(net "M_C_CPU1_SA_DQ<2>")
	)
	(segment
		(start 88.451182 -286.794702)
		(end 88.442292 -286.799782)
		(width 0.088646)
		(layer "In4.Cu")
		(net "M_C_CPU1_SA_DQ<2>")
	)
	(segment
		(start 88.629744 -286.4612)
		(end 88.629744 -286.475424)
		(width 0.088646)
		(layer "In4.Cu")
		(net "M_C_CPU1_SA_DQ<2>")
	)
	(segment
		(start 57.933844 -315.738256)
		(end 56.747664 -316.924436)
		(width 0.18288)
		(layer "In4.Cu")
		(net "M_C_CPU1_SA_DQ<2>")
	)
	(segment
		(start 40.951404 -317.580772)
		(end 39.37 -315.999368)
		(width 0.18288)
		(layer "In4.Cu")
		(net "M_C_CPU1_SA_DQ<2>")
	)
	(segment
		(start 45.465492 -318.441578)
		(end 43.387264 -317.580772)
		(width 0.18288)
		(layer "In4.Cu")
		(net "M_C_CPU1_SA_DQ<2>")
	)
	(segment
		(start 61.371226 -316.082426)
		(end 60.828428 -316.625224)
		(width 0.18288)
		(layer "In4.Cu")
		(net "M_C_CPU1_SA_DQ<2>")
	)
	(segment
		(start 38.487858 -317.30442)
		(end 38.129718 -317.30442)
		(width 0.18288)
		(layer "In4.Cu")
		(net "M_C_CPU1_SA_DQ<2>")
	)
	(segment
		(start 65.828926 -314.101226)
		(end 64.609472 -315.32068)
		(width 0.18288)
		(layer "In4.Cu")
		(net "M_C_CPU1_SA_DQ<2>")
	)
	(segment
		(start 91.919298 -282.390342)
		(end 91.919298 -282.405836)
		(width 0.088646)
		(layer "In4.Cu")
		(net "M_C_CPU1_SA_DQ<2>")
	)
	(segment
		(start 38.129718 -317.30442)
		(end 37.946838 -317.12154)
		(width 0.18288)
		(layer "In4.Cu")
		(net "M_C_CPU1_SA_DQ<2>")
	)
	(segment
		(start 73.56602 -304.988976)
		(end 73.56602 -307.378608)
		(width 0.18288)
		(layer "In4.Cu")
		(net "M_C_CPU1_SA_DQ<2>")
	)
	(segment
		(start 92.210636 -280.283412)
		(end 92.201746 -280.288492)
		(width 0.088646)
		(layer "In4.Cu")
		(net "M_C_CPU1_SA_DQ<2>")
	)
	(segment
		(start 43.387264 -317.580772)
		(end 40.951404 -317.580772)
		(width 0.18288)
		(layer "In4.Cu")
		(net "M_C_CPU1_SA_DQ<2>")
	)
	(segment
		(start 62.234826 -316.082426)
		(end 61.371226 -316.082426)
		(width 0.18288)
		(layer "In4.Cu")
		(net "M_C_CPU1_SA_DQ<2>")
	)
	(segment
		(start 88.159844 -287.279334)
		(end 88.159844 -287.28924)
		(width 0.088646)
		(layer "In4.Cu")
		(net "M_C_CPU1_SA_DQ<2>")
	)
	(segment
		(start 38.647878 -316.227968)
		(end 38.647878 -317.1444)
		(width 0.18288)
		(layer "In4.Cu")
		(net "M_C_CPU1_SA_DQ<2>")
	)
	(segment
		(start 80.164686 -298.39031)
		(end 73.56602 -304.988976)
		(width 0.18288)
		(layer "In4.Cu")
		(net "M_C_CPU1_SA_DQ<2>")
	)
	(segment
		(start 37.946838 -317.12154)
		(end 37.946838 -316.159388)
		(width 0.18288)
		(layer "In4.Cu")
		(net "M_C_CPU1_SA_DQ<2>")
	)
	(segment
		(start 62.996572 -315.32068)
		(end 62.234826 -316.082426)
		(width 0.18288)
		(layer "In4.Cu")
		(net "M_C_CPU1_SA_DQ<2>")
	)
	(segment
		(start 38.647878 -317.1444)
		(end 38.487858 -317.30442)
		(width 0.18288)
		(layer "In4.Cu")
		(net "M_C_CPU1_SA_DQ<2>")
	)
	(segment
		(start 73.56602 -307.378608)
		(end 66.843402 -314.101226)
		(width 0.18288)
		(layer "In4.Cu")
		(net "M_C_CPU1_SA_DQ<2>")
	)
	(segment
		(start 87.981282 -287.608518)
		(end 87.972392 -287.613598)
		(width 0.088646)
		(layer "In4.Cu")
		(net "M_C_CPU1_SA_DQ<2>")
	)
	(segment
		(start 91.919298 -280.759662)
		(end 91.919298 -280.793698)
		(width 0.088646)
		(layer "In4.Cu")
		(net "M_C_CPU1_SA_DQ<2>")
	)
	(segment
		(start 39.37 -315.999368)
		(end 38.876478 -315.999368)
		(width 0.18288)
		(layer "In4.Cu")
		(net "M_C_CPU1_SA_DQ<2>")
	)
	(segment
		(start 86.189058 -287.874964)
		(end 85.646768 -287.874964)
		(width 0.18288)
		(layer "In4.Cu")
		(net "M_C_CPU1_SA_DQ<2>")
	)
	(segment
		(start 37.786818 -315.999368)
		(end 36.509452 -315.999368)
		(width 0.18288)
		(layer "In4.Cu")
		(net "M_C_CPU1_SA_DQ<2>")
	)
	(segment
		(start 55.084726 -317.657988)
		(end 53.387244 -317.657988)
		(width 0.18288)
		(layer "In4.Cu")
		(net "M_C_CPU1_SA_DQ<2>")
	)
	(segment
		(start 91.740736 -282.725114)
		(end 91.731846 -282.730194)
		(width 0.088646)
		(layer "In4.Cu")
		(net "M_C_CPU1_SA_DQ<2>")
	)
	(segment
		(start 92.210382 -281.911298)
		(end 92.201492 -281.916378)
		(width 0.088646)
		(layer "In4.Cu")
		(net "M_C_CPU1_SA_DQ<2>")
	)
	(segment
		(start 37.946838 -316.159388)
		(end 37.786818 -315.999368)
		(width 0.18288)
		(layer "In4.Cu")
		(net "M_C_CPU1_SA_DQ<2>")
	)
	(segment
		(start 90.800682 -284.353)
		(end 90.791792 -284.35808)
		(width 0.088646)
		(layer "In4.Cu")
		(net "M_C_CPU1_SA_DQ<2>")
	)
	(segment
		(start 88.921082 -285.980632)
		(end 88.912192 -285.985712)
		(width 0.088646)
		(layer "In4.Cu")
		(net "M_C_CPU1_SA_DQ<2>")
	)
	(segment
		(start 89.390982 -285.166816)
		(end 89.382092 -285.171896)
		(width 0.088646)
		(layer "In4.Cu")
		(net "M_C_CPU1_SA_DQ<2>")
	)
	(segment
		(start 59.646312 -316.625224)
		(end 58.759344 -315.738256)
		(width 0.18288)
		(layer "In4.Cu")
		(net "M_C_CPU1_SA_DQ<2>")
	)
	(segment
		(start 89.099644 -285.651448)
		(end 89.099644 -285.661354)
		(width 0.088646)
		(layer "In4.Cu")
		(net "M_C_CPU1_SA_DQ<2>")
	)
	(segment
		(start 86.743794 -287.874964)
		(end 86.189058 -287.874964)
		(width 0.088646)
		(layer "In4.Cu")
		(net "M_C_CPU1_SA_DQ<2>")
	)
	(segment
		(start 83.725258 -289.796474)
		(end 80.164686 -298.39031)
		(width 0.18288)
		(layer "In4.Cu")
		(net "M_C_CPU1_SA_DQ<2>")
	)
	(segment
		(start 55.818278 -316.924436)
		(end 55.084726 -317.657988)
		(width 0.18288)
		(layer "In4.Cu")
		(net "M_C_CPU1_SA_DQ<2>")
	)
	(segment
		(start 64.609472 -315.32068)
		(end 62.996572 -315.32068)
		(width 0.18288)
		(layer "In4.Cu")
		(net "M_C_CPU1_SA_DQ<2>")
	)
	(segment
		(start 66.843402 -314.101226)
		(end 65.828926 -314.101226)
		(width 0.18288)
		(layer "In4.Cu")
		(net "M_C_CPU1_SA_DQ<2>")
	)
	(segment
		(start 36.509452 -315.999368)
		(end 35.976814 -315.46673)
		(width 0.18288)
		(layer "In4.Cu")
		(net "M_C_CPU1_SA_DQ<2>")
	)
	(segment
		(start 92.389198 -279.799542)
		(end 92.389198 -279.964134)
		(width 0.088646)
		(layer "In4.Cu")
		(net "M_C_CPU1_SA_DQ<2>")
	)
	(segment
		(start 89.569544 -284.837632)
		(end 89.569544 -284.847538)
		(width 0.088646)
		(layer "In4.Cu")
		(net "M_C_CPU1_SA_DQ<2>")
	)
	(segment
		(start 56.747664 -316.924436)
		(end 55.818278 -316.924436)
		(width 0.18288)
		(layer "In4.Cu")
		(net "M_C_CPU1_SA_DQ<2>")
	)
	(segment
		(start 85.646768 -287.874964)
		(end 83.725258 -289.796474)
		(width 0.18288)
		(layer "In4.Cu")
		(net "M_C_CPU1_SA_DQ<2>")
	)
	(segment
		(start 93.423994 -279.150318)
		(end 92.719398 -278.74341)
		(width 0.088646)
		(layer "In4.Cu")
		(net "M_C_CPU1_SA_DQ<2>")
	)
	(segment
		(start 38.876478 -315.999368)
		(end 38.647878 -316.227968)
		(width 0.18288)
		(layer "In4.Cu")
		(net "M_C_CPU1_SA_DQ<2>")
	)
	(segment
		(start 52.603654 -318.441578)
		(end 45.465492 -318.441578)
		(width 0.18288)
		(layer "In4.Cu")
		(net "M_C_CPU1_SA_DQ<2>")
	)
	(segment
		(start 60.828428 -316.625224)
		(end 59.646312 -316.625224)
		(width 0.18288)
		(layer "In4.Cu")
		(net "M_C_CPU1_SA_DQ<2>")
	)
	(segment
		(start 90.979244 -284.023816)
		(end 90.979244 -284.033722)
		(width 0.088646)
		(layer "In4.Cu")
		(net "M_C_CPU1_SA_DQ<2>")
	)
	(segment
		(start 53.387244 -317.657988)
		(end 52.603654 -318.441578)
		(width 0.18288)
		(layer "In4.Cu")
		(net "M_C_CPU1_SA_DQ<2>")
	)
	(segment
		(start 92.201492 -281.267662)
		(end 92.210382 -281.272742)
		(width 0.088646)
		(layer "In4.Cu")
		(net "M_C_CPU1_SA_DQ<2>")
	)
	(segment
		(start 92.244418 -279.554432)
		(end 92.249244 -279.557226)
		(width 0.088646)
		(layer "In4.Cu")
		(net "M_C_CPU1_SA_DQ<2>")
	)
	(segment
		(start 86.915498 -287.70326)
		(end 86.743794 -287.874964)
		(width 0.088646)
		(layer "In4.Cu")
		(net "M_C_CPU1_SA_DQ<2>")
	)
	(segment
		(start 91.270582 -283.539184)
		(end 91.261692 -283.544264)
		(width 0.088646)
		(layer "In4.Cu")
		(net "M_C_CPU1_SA_DQ<2>")
	)
	(segment
		(start 58.759344 -315.738256)
		(end 57.933844 -315.738256)
		(width 0.18288)
		(layer "In4.Cu")
		(net "M_C_CPU1_SA_DQ<2>")
	)
	(arc
		(start 87.972392 -287.613598)
		(mid 87.785194 -287.663741)
		(end 87.597996 -287.613598)
		(width 0.088646)
		(layer "In4.Cu")
		(net "M_C_CPU1_SA_DQ<2>")
	)
	(arc
		(start 92.014294 -279.150318)
		(mid 92.075857 -279.382841)
		(end 92.244418 -279.554432)
		(width 0.088646)
		(layer "In4.Cu")
		(net "M_C_CPU1_SA_DQ<2>")
	)
	(arc
		(start 92.201746 -280.288492)
		(mid 91.99946 -280.487473)
		(end 91.919298 -280.759662)
		(width 0.088646)
		(layer "In4.Cu")
		(net "M_C_CPU1_SA_DQ<2>")
	)
	(arc
		(start 90.417396 -284.35808)
		(mid 90.134694 -284.282304)
		(end 89.851992 -284.35808)
		(width 0.088646)
		(layer "In4.Cu")
		(net "M_C_CPU1_SA_DQ<2>")
	)
	(arc
		(start 92.389198 -279.964134)
		(mid 92.341519 -280.147034)
		(end 92.210636 -280.283412)
		(width 0.088646)
		(layer "In4.Cu")
		(net "M_C_CPU1_SA_DQ<2>")
	)
	(arc
		(start 91.731846 -282.730194)
		(mid 91.528365 -282.930998)
		(end 91.449144 -283.205682)
		(width 0.088646)
		(layer "In4.Cu")
		(net "M_C_CPU1_SA_DQ<2>")
	)
	(arc
		(start 92.719144 -278.74341)
		(mid 92.484194 -278.68045)
		(end 92.249244 -278.74341)
		(width 0.088646)
		(layer "In4.Cu")
		(net "M_C_CPU1_SA_DQ<2>")
	)
	(arc
		(start 88.629744 -286.475424)
		(mid 88.582065 -286.658324)
		(end 88.451182 -286.794702)
		(width 0.088646)
		(layer "In4.Cu")
		(net "M_C_CPU1_SA_DQ<2>")
	)
	(arc
		(start 89.382092 -285.171896)
		(mid 89.177757 -285.374501)
		(end 89.099644 -285.651448)
		(width 0.088646)
		(layer "In4.Cu")
		(net "M_C_CPU1_SA_DQ<2>")
	)
	(arc
		(start 87.597996 -287.613598)
		(mid 87.315294 -287.537822)
		(end 87.032592 -287.613598)
		(width 0.088646)
		(layer "In4.Cu")
		(net "M_C_CPU1_SA_DQ<2>")
	)
	(arc
		(start 90.979244 -284.033722)
		(mid 90.931565 -284.216622)
		(end 90.800682 -284.353)
		(width 0.088646)
		(layer "In4.Cu")
		(net "M_C_CPU1_SA_DQ<2>")
	)
	(arc
		(start 91.261692 -283.544264)
		(mid 91.057357 -283.746869)
		(end 90.979244 -284.023816)
		(width 0.088646)
		(layer "In4.Cu")
		(net "M_C_CPU1_SA_DQ<2>")
	)
	(arc
		(start 91.919298 -280.793698)
		(mid 91.998668 -281.067432)
		(end 92.201492 -281.267662)
		(width 0.088646)
		(layer "In4.Cu")
		(net "M_C_CPU1_SA_DQ<2>")
	)
	(arc
		(start 92.249244 -279.557226)
		(mid 92.351729 -279.659616)
		(end 92.389198 -279.799542)
		(width 0.088646)
		(layer "In4.Cu")
		(net "M_C_CPU1_SA_DQ<2>")
	)
	(arc
		(start 91.449144 -283.219906)
		(mid 91.401465 -283.402806)
		(end 91.270582 -283.539184)
		(width 0.088646)
		(layer "In4.Cu")
		(net "M_C_CPU1_SA_DQ<2>")
	)
	(arc
		(start 89.851992 -284.35808)
		(mid 89.647657 -284.560685)
		(end 89.569544 -284.837632)
		(width 0.088646)
		(layer "In4.Cu")
		(net "M_C_CPU1_SA_DQ<2>")
	)
	(arc
		(start 89.099644 -285.661354)
		(mid 89.051965 -285.844254)
		(end 88.921082 -285.980632)
		(width 0.088646)
		(layer "In4.Cu")
		(net "M_C_CPU1_SA_DQ<2>")
	)
	(arc
		(start 92.201492 -281.916378)
		(mid 91.998669 -282.116609)
		(end 91.919298 -282.390342)
		(width 0.088646)
		(layer "In4.Cu")
		(net "M_C_CPU1_SA_DQ<2>")
	)
	(arc
		(start 92.210382 -281.272742)
		(mid 92.388979 -281.59202)
		(end 92.210382 -281.911298)
		(width 0.088646)
		(layer "In4.Cu")
		(net "M_C_CPU1_SA_DQ<2>")
	)
	(arc
		(start 89.569544 -284.847538)
		(mid 89.521865 -285.030438)
		(end 89.390982 -285.166816)
		(width 0.088646)
		(layer "In4.Cu")
		(net "M_C_CPU1_SA_DQ<2>")
	)
	(arc
		(start 88.159844 -287.28924)
		(mid 88.112165 -287.47214)
		(end 87.981282 -287.608518)
		(width 0.088646)
		(layer "In4.Cu")
		(net "M_C_CPU1_SA_DQ<2>")
	)
	(arc
		(start 88.442292 -286.799782)
		(mid 88.237957 -287.002387)
		(end 88.159844 -287.279334)
		(width 0.088646)
		(layer "In4.Cu")
		(net "M_C_CPU1_SA_DQ<2>")
	)
	(arc
		(start 92.249244 -278.74341)
		(mid 92.077272 -278.915392)
		(end 92.014294 -279.150318)
		(width 0.088646)
		(layer "In4.Cu")
		(net "M_C_CPU1_SA_DQ<2>")
	)
	(arc
		(start 91.919298 -282.405836)
		(mid 91.871619 -282.588736)
		(end 91.740736 -282.725114)
		(width 0.088646)
		(layer "In4.Cu")
		(net "M_C_CPU1_SA_DQ<2>")
	)
	(arc
		(start 87.032592 -287.613598)
		(mid 86.971114 -287.6546)
		(end 86.915498 -287.70326)
		(width 0.088646)
		(layer "In4.Cu")
		(net "M_C_CPU1_SA_DQ<2>")
	)
	(arc
		(start 88.912192 -285.985712)
		(mid 88.708887 -286.186578)
		(end 88.629744 -286.4612)
		(width 0.088646)
		(layer "In4.Cu")
		(net "M_C_CPU1_SA_DQ<2>")
	)
	(arc
		(start 90.791792 -284.35808)
		(mid 90.604594 -284.408223)
		(end 90.417396 -284.35808)
		(width 0.088646)
		(layer "In4.Cu")
		(net "M_C_CPU1_SA_DQ<2>")
	)
	(segment
		(start 28.198318 -280.191718)
		(end 28.529026 -280.191718)
		(width 0.101854)
		(layer "F.Cu")
		(net "M_C_CPU1_SA_DQ<29>")
	)
	(segment
		(start 31.876746 -280.61666)
		(end 30.771846 -280.61666)
		(width 0.20066)
		(layer "F.Cu")
		(net "M_C_CPU1_SA_DQ<29>")
	)
	(segment
		(start 26.2128 -280.191718)
		(end 28.198318 -280.191718)
		(width 0.1016)
		(layer "F.Cu")
		(net "M_C_CPU1_SA_DQ<29>")
	)
	(segment
		(start 95.773494 -263.150604)
		(end 95.773494 -263.68629)
		(width 0.20066)
		(layer "F.Cu")
		(net "M_C_CPU1_SA_DQ<29>")
	)
	(segment
		(start 23.228046 -280.61666)
		(end 24.562308 -280.61666)
		(width 0.20066)
		(layer "F.Cu")
		(net "M_C_CPU1_SA_DQ<29>")
	)
	(segment
		(start 24.562308 -280.61666)
		(end 24.773636 -280.827988)
		(width 0.20066)
		(layer "F.Cu")
		(net "M_C_CPU1_SA_DQ<29>")
	)
	(segment
		(start 25.27808 -280.827988)
		(end 25.432512 -280.673556)
		(width 0.20066)
		(layer "F.Cu")
		(net "M_C_CPU1_SA_DQ<29>")
	)
	(segment
		(start 25.595072 -280.182828)
		(end 26.20391 -280.182828)
		(width 0.20066)
		(layer "F.Cu")
		(net "M_C_CPU1_SA_DQ<29>")
	)
	(segment
		(start 28.707588 -280.191718)
		(end 29.13253 -280.61666)
		(width 0.20066)
		(layer "F.Cu")
		(net "M_C_CPU1_SA_DQ<29>")
	)
	(segment
		(start 29.13253 -280.61666)
		(end 30.771846 -280.61666)
		(width 0.20066)
		(layer "F.Cu")
		(net "M_C_CPU1_SA_DQ<29>")
	)
	(segment
		(start 95.773494 -263.68629)
		(end 95.773748 -263.686544)
		(width 0.20066)
		(layer "F.Cu")
		(net "M_C_CPU1_SA_DQ<29>")
	)
	(segment
		(start 25.432512 -280.673556)
		(end 25.432512 -280.345388)
		(width 0.20066)
		(layer "F.Cu")
		(net "M_C_CPU1_SA_DQ<29>")
	)
	(segment
		(start 28.529026 -280.191718)
		(end 28.707588 -280.191718)
		(width 0.20066)
		(layer "F.Cu")
		(net "M_C_CPU1_SA_DQ<29>")
	)
	(segment
		(start 25.432512 -280.345388)
		(end 25.595072 -280.182828)
		(width 0.20066)
		(layer "F.Cu")
		(net "M_C_CPU1_SA_DQ<29>")
	)
	(segment
		(start 26.20391 -280.182828)
		(end 26.2128 -280.191718)
		(width 0.1016)
		(layer "F.Cu")
		(net "M_C_CPU1_SA_DQ<29>")
	)
	(segment
		(start 24.773636 -280.827988)
		(end 25.27808 -280.827988)
		(width 0.20066)
		(layer "F.Cu")
		(net "M_C_CPU1_SA_DQ<29>")
	)
	(segment
		(start 90.887296 -263.361932)
		(end 90.881454 -263.365488)
		(width 0.088646)
		(layer "In6.Cu")
		(net "M_C_CPU1_SA_DQ<29>")
	)
	(segment
		(start 59.412124 -273.265138)
		(end 58.748168 -273.929094)
		(width 0.18288)
		(layer "In6.Cu")
		(net "M_C_CPU1_SA_DQ<29>")
	)
	(segment
		(start 83.652106 -264.68451)
		(end 83.652106 -265.022584)
		(width 0.088646)
		(layer "In6.Cu")
		(net "M_C_CPU1_SA_DQ<29>")
	)
	(segment
		(start 34.374328 -281.041602)
		(end 34.049208 -281.041602)
		(width 0.18288)
		(layer "In6.Cu")
		(net "M_C_CPU1_SA_DQ<29>")
	)
	(segment
		(start 94.646496 -263.361932)
		(end 94.640654 -263.365488)
		(width 0.088646)
		(layer "In6.Cu")
		(net "M_C_CPU1_SA_DQ<29>")
	)
	(segment
		(start 78.812644 -266.556236)
		(end 73.686162 -266.556236)
		(width 0.18288)
		(layer "In6.Cu")
		(net "M_C_CPU1_SA_DQ<29>")
	)
	(segment
		(start 50.10912 -275.94179)
		(end 49.259236 -276.791674)
		(width 0.18288)
		(layer "In6.Cu")
		(net "M_C_CPU1_SA_DQ<29>")
	)
	(segment
		(start 93.706696 -263.361932)
		(end 93.700854 -263.365488)
		(width 0.088646)
		(layer "In6.Cu")
		(net "M_C_CPU1_SA_DQ<29>")
	)
	(segment
		(start 91.827096 -263.361932)
		(end 91.821254 -263.365488)
		(width 0.088646)
		(layer "In6.Cu")
		(net "M_C_CPU1_SA_DQ<29>")
	)
	(segment
		(start 35.430968 -281.041602)
		(end 35.248088 -281.224482)
		(width 0.18288)
		(layer "In6.Cu")
		(net "M_C_CPU1_SA_DQ<29>")
	)
	(segment
		(start 53.184044 -274.585938)
		(end 51.828192 -275.94179)
		(width 0.18288)
		(layer "In6.Cu")
		(net "M_C_CPU1_SA_DQ<29>")
	)
	(segment
		(start 49.259236 -276.791674)
		(end 44.89831 -276.791674)
		(width 0.18288)
		(layer "In6.Cu")
		(net "M_C_CPU1_SA_DQ<29>")
	)
	(segment
		(start 94.652338 -263.35863)
		(end 94.646496 -263.361932)
		(width 0.088646)
		(layer "In6.Cu")
		(net "M_C_CPU1_SA_DQ<29>")
	)
	(segment
		(start 33.866328 -281.224482)
		(end 33.866328 -281.482292)
		(width 0.18288)
		(layer "In6.Cu")
		(net "M_C_CPU1_SA_DQ<29>")
	)
	(segment
		(start 90.893138 -263.35863)
		(end 90.887296 -263.361932)
		(width 0.088646)
		(layer "In6.Cu")
		(net "M_C_CPU1_SA_DQ<29>")
	)
	(segment
		(start 93.712538 -263.35863)
		(end 93.706696 -263.361932)
		(width 0.088646)
		(layer "In6.Cu")
		(net "M_C_CPU1_SA_DQ<29>")
	)
	(segment
		(start 33.175448 -281.224482)
		(end 32.992568 -281.041602)
		(width 0.18288)
		(layer "In6.Cu")
		(net "M_C_CPU1_SA_DQ<29>")
	)
	(segment
		(start 95.773748 -263.686544)
		(end 96.086422 -263.686544)
		(width 0.088646)
		(layer "In6.Cu")
		(net "M_C_CPU1_SA_DQ<29>")
	)
	(segment
		(start 37.268658 -280.243026)
		(end 36.470082 -281.041602)
		(width 0.18288)
		(layer "In6.Cu")
		(net "M_C_CPU1_SA_DQ<29>")
	)
	(segment
		(start 33.358328 -281.665172)
		(end 33.175448 -281.482292)
		(width 0.18288)
		(layer "In6.Cu")
		(net "M_C_CPU1_SA_DQ<29>")
	)
	(segment
		(start 35.248088 -281.224482)
		(end 35.248088 -281.482292)
		(width 0.18288)
		(layer "In6.Cu")
		(net "M_C_CPU1_SA_DQ<29>")
	)
	(segment
		(start 95.592138 -263.35863)
		(end 95.586296 -263.361932)
		(width 0.088646)
		(layer "In6.Cu")
		(net "M_C_CPU1_SA_DQ<29>")
	)
	(segment
		(start 36.470082 -281.041602)
		(end 35.430968 -281.041602)
		(width 0.18288)
		(layer "In6.Cu")
		(net "M_C_CPU1_SA_DQ<29>")
	)
	(segment
		(start 73.686162 -266.556236)
		(end 70.334632 -267.9446)
		(width 0.18288)
		(layer "In6.Cu")
		(net "M_C_CPU1_SA_DQ<29>")
	)
	(segment
		(start 92.772738 -263.35863)
		(end 92.766896 -263.361932)
		(width 0.088646)
		(layer "In6.Cu")
		(net "M_C_CPU1_SA_DQ<29>")
	)
	(segment
		(start 34.557208 -281.482292)
		(end 34.557208 -281.224482)
		(width 0.18288)
		(layer "In6.Cu")
		(net "M_C_CPU1_SA_DQ<29>")
	)
	(segment
		(start 32.992568 -281.041602)
		(end 32.301688 -281.041602)
		(width 0.18288)
		(layer "In6.Cu")
		(net "M_C_CPU1_SA_DQ<29>")
	)
	(segment
		(start 92.766896 -263.361932)
		(end 92.761054 -263.365488)
		(width 0.088646)
		(layer "In6.Cu")
		(net "M_C_CPU1_SA_DQ<29>")
	)
	(segment
		(start 89.011506 -263.3599)
		(end 89.007696 -263.361932)
		(width 0.088646)
		(layer "In6.Cu")
		(net "M_C_CPU1_SA_DQ<29>")
	)
	(segment
		(start 88.442546 -263.361932)
		(end 88.442292 -263.362186)
		(width 0.088646)
		(layer "In6.Cu")
		(net "M_C_CPU1_SA_DQ<29>")
	)
	(segment
		(start 34.049208 -281.041602)
		(end 33.866328 -281.224482)
		(width 0.18288)
		(layer "In6.Cu")
		(net "M_C_CPU1_SA_DQ<29>")
	)
	(segment
		(start 39.971726 -280.243026)
		(end 37.268658 -280.243026)
		(width 0.18288)
		(layer "In6.Cu")
		(net "M_C_CPU1_SA_DQ<29>")
	)
	(segment
		(start 84.324444 -263.577578)
		(end 84.219542 -263.68248)
		(width 0.088646)
		(layer "In6.Cu")
		(net "M_C_CPU1_SA_DQ<29>")
	)
	(segment
		(start 62.730634 -273.265138)
		(end 59.412124 -273.265138)
		(width 0.18288)
		(layer "In6.Cu")
		(net "M_C_CPU1_SA_DQ<29>")
	)
	(segment
		(start 65.077848 -272.394426)
		(end 63.601346 -272.394426)
		(width 0.18288)
		(layer "In6.Cu")
		(net "M_C_CPU1_SA_DQ<29>")
	)
	(segment
		(start 84.219542 -264.117074)
		(end 83.652106 -264.68451)
		(width 0.088646)
		(layer "In6.Cu")
		(net "M_C_CPU1_SA_DQ<29>")
	)
	(segment
		(start 65.501774 -271.9705)
		(end 65.077848 -272.394426)
		(width 0.18288)
		(layer "In6.Cu")
		(net "M_C_CPU1_SA_DQ<29>")
	)
	(segment
		(start 54.706774 -274.585938)
		(end 53.184044 -274.585938)
		(width 0.18288)
		(layer "In6.Cu")
		(net "M_C_CPU1_SA_DQ<29>")
	)
	(segment
		(start 66.308732 -271.9705)
		(end 65.501774 -271.9705)
		(width 0.18288)
		(layer "In6.Cu")
		(net "M_C_CPU1_SA_DQ<29>")
	)
	(segment
		(start 63.601346 -272.394426)
		(end 62.730634 -273.265138)
		(width 0.18288)
		(layer "In6.Cu")
		(net "M_C_CPU1_SA_DQ<29>")
	)
	(segment
		(start 83.442302 -265.232388)
		(end 83.039204 -265.232388)
		(width 0.088646)
		(layer "In6.Cu")
		(net "M_C_CPU1_SA_DQ<29>")
	)
	(segment
		(start 33.175448 -281.482292)
		(end 33.175448 -281.224482)
		(width 0.18288)
		(layer "In6.Cu")
		(net "M_C_CPU1_SA_DQ<29>")
	)
	(segment
		(start 58.748168 -273.929094)
		(end 55.363618 -273.929094)
		(width 0.18288)
		(layer "In6.Cu")
		(net "M_C_CPU1_SA_DQ<29>")
	)
	(segment
		(start 34.557208 -281.224482)
		(end 34.374328 -281.041602)
		(width 0.18288)
		(layer "In6.Cu")
		(net "M_C_CPU1_SA_DQ<29>")
	)
	(segment
		(start 51.828192 -275.94179)
		(end 50.10912 -275.94179)
		(width 0.18288)
		(layer "In6.Cu")
		(net "M_C_CPU1_SA_DQ<29>")
	)
	(segment
		(start 40.748458 -279.466294)
		(end 39.971726 -280.243026)
		(width 0.18288)
		(layer "In6.Cu")
		(net "M_C_CPU1_SA_DQ<29>")
	)
	(segment
		(start 91.832938 -263.35863)
		(end 91.827096 -263.361932)
		(width 0.088646)
		(layer "In6.Cu")
		(net "M_C_CPU1_SA_DQ<29>")
	)
	(segment
		(start 33.683448 -281.665172)
		(end 33.358328 -281.665172)
		(width 0.18288)
		(layer "In6.Cu")
		(net "M_C_CPU1_SA_DQ<29>")
	)
	(segment
		(start 33.866328 -281.482292)
		(end 33.683448 -281.665172)
		(width 0.18288)
		(layer "In6.Cu")
		(net "M_C_CPU1_SA_DQ<29>")
	)
	(segment
		(start 82.008726 -265.232388)
		(end 78.812644 -266.556236)
		(width 0.18288)
		(layer "In6.Cu")
		(net "M_C_CPU1_SA_DQ<29>")
	)
	(segment
		(start 34.740088 -281.665172)
		(end 34.557208 -281.482292)
		(width 0.18288)
		(layer "In6.Cu")
		(net "M_C_CPU1_SA_DQ<29>")
	)
	(segment
		(start 89.951814 -263.359392)
		(end 89.947496 -263.361932)
		(width 0.088646)
		(layer "In6.Cu")
		(net "M_C_CPU1_SA_DQ<29>")
	)
	(segment
		(start 55.363618 -273.929094)
		(end 54.706774 -274.585938)
		(width 0.18288)
		(layer "In6.Cu")
		(net "M_C_CPU1_SA_DQ<29>")
	)
	(segment
		(start 32.301688 -281.041602)
		(end 31.876746 -280.61666)
		(width 0.18288)
		(layer "In6.Cu")
		(net "M_C_CPU1_SA_DQ<29>")
	)
	(segment
		(start 70.334632 -267.9446)
		(end 66.308732 -271.9705)
		(width 0.18288)
		(layer "In6.Cu")
		(net "M_C_CPU1_SA_DQ<29>")
	)
	(segment
		(start 83.039204 -265.232388)
		(end 82.008726 -265.232388)
		(width 0.18288)
		(layer "In6.Cu")
		(net "M_C_CPU1_SA_DQ<29>")
	)
	(segment
		(start 44.89831 -276.791674)
		(end 42.22369 -279.466294)
		(width 0.18288)
		(layer "In6.Cu")
		(net "M_C_CPU1_SA_DQ<29>")
	)
	(segment
		(start 42.22369 -279.466294)
		(end 40.748458 -279.466294)
		(width 0.18288)
		(layer "In6.Cu")
		(net "M_C_CPU1_SA_DQ<29>")
	)
	(segment
		(start 84.219542 -263.68248)
		(end 84.219542 -264.117074)
		(width 0.088646)
		(layer "In6.Cu")
		(net "M_C_CPU1_SA_DQ<29>")
	)
	(segment
		(start 83.652106 -265.022584)
		(end 83.442302 -265.232388)
		(width 0.088646)
		(layer "In6.Cu")
		(net "M_C_CPU1_SA_DQ<29>")
	)
	(segment
		(start 89.007696 -263.361932)
		(end 89.001854 -263.365488)
		(width 0.088646)
		(layer "In6.Cu")
		(net "M_C_CPU1_SA_DQ<29>")
	)
	(segment
		(start 35.065208 -281.665172)
		(end 34.740088 -281.665172)
		(width 0.18288)
		(layer "In6.Cu")
		(net "M_C_CPU1_SA_DQ<29>")
	)
	(segment
		(start 96.086422 -263.686544)
		(end 96.143826 -263.628886)
		(width 0.088646)
		(layer "In6.Cu")
		(net "M_C_CPU1_SA_DQ<29>")
	)
	(segment
		(start 95.586296 -263.361932)
		(end 95.580454 -263.365488)
		(width 0.088646)
		(layer "In6.Cu")
		(net "M_C_CPU1_SA_DQ<29>")
	)
	(segment
		(start 35.248088 -281.482292)
		(end 35.065208 -281.665172)
		(width 0.18288)
		(layer "In6.Cu")
		(net "M_C_CPU1_SA_DQ<29>")
	)
	(arc
		(start 94.081346 -263.361932)
		(mid 93.897392 -263.311803)
		(end 93.712538 -263.35863)
		(width 0.088646)
		(layer "In6.Cu")
		(net "M_C_CPU1_SA_DQ<29>")
	)
	(arc
		(start 93.700854 -263.365488)
		(mid 93.420719 -263.437771)
		(end 93.141546 -263.361932)
		(width 0.088646)
		(layer "In6.Cu")
		(net "M_C_CPU1_SA_DQ<29>")
	)
	(arc
		(start 88.067896 -263.362186)
		(mid 87.785194 -263.437928)
		(end 87.502492 -263.362186)
		(width 0.088646)
		(layer "In6.Cu")
		(net "M_C_CPU1_SA_DQ<29>")
	)
	(arc
		(start 94.640654 -263.365488)
		(mid 94.360519 -263.437771)
		(end 94.081346 -263.361932)
		(width 0.088646)
		(layer "In6.Cu")
		(net "M_C_CPU1_SA_DQ<29>")
	)
	(arc
		(start 88.442292 -263.362186)
		(mid 88.255094 -263.312043)
		(end 88.067896 -263.362186)
		(width 0.088646)
		(layer "In6.Cu")
		(net "M_C_CPU1_SA_DQ<29>")
	)
	(arc
		(start 90.322146 -263.361932)
		(mid 90.137309 -263.311671)
		(end 89.951814 -263.359392)
		(width 0.088646)
		(layer "In6.Cu")
		(net "M_C_CPU1_SA_DQ<29>")
	)
	(arc
		(start 93.141546 -263.361932)
		(mid 92.957592 -263.311803)
		(end 92.772738 -263.35863)
		(width 0.088646)
		(layer "In6.Cu")
		(net "M_C_CPU1_SA_DQ<29>")
	)
	(arc
		(start 84.84489 -263.424924)
		(mid 84.56515 -263.434744)
		(end 84.324444 -263.577578)
		(width 0.088646)
		(layer "In6.Cu")
		(net "M_C_CPU1_SA_DQ<29>")
	)
	(arc
		(start 89.001854 -263.365488)
		(mid 88.721719 -263.437771)
		(end 88.442546 -263.361932)
		(width 0.088646)
		(layer "In6.Cu")
		(net "M_C_CPU1_SA_DQ<29>")
	)
	(arc
		(start 86.188296 -263.362186)
		(mid 85.905594 -263.437928)
		(end 85.622892 -263.362186)
		(width 0.088646)
		(layer "In6.Cu")
		(net "M_C_CPU1_SA_DQ<29>")
	)
	(arc
		(start 85.622892 -263.362186)
		(mid 85.435694 -263.312043)
		(end 85.248496 -263.362186)
		(width 0.088646)
		(layer "In6.Cu")
		(net "M_C_CPU1_SA_DQ<29>")
	)
	(arc
		(start 91.261946 -263.361932)
		(mid 91.077992 -263.311803)
		(end 90.893138 -263.35863)
		(width 0.088646)
		(layer "In6.Cu")
		(net "M_C_CPU1_SA_DQ<29>")
	)
	(arc
		(start 92.761054 -263.365488)
		(mid 92.480919 -263.437771)
		(end 92.201746 -263.361932)
		(width 0.088646)
		(layer "In6.Cu")
		(net "M_C_CPU1_SA_DQ<29>")
	)
	(arc
		(start 95.960946 -263.361932)
		(mid 95.776992 -263.311803)
		(end 95.592138 -263.35863)
		(width 0.088646)
		(layer "In6.Cu")
		(net "M_C_CPU1_SA_DQ<29>")
	)
	(arc
		(start 95.021146 -263.361932)
		(mid 94.837192 -263.311803)
		(end 94.652338 -263.35863)
		(width 0.088646)
		(layer "In6.Cu")
		(net "M_C_CPU1_SA_DQ<29>")
	)
	(arc
		(start 87.128096 -263.362186)
		(mid 86.845394 -263.437928)
		(end 86.562692 -263.362186)
		(width 0.088646)
		(layer "In6.Cu")
		(net "M_C_CPU1_SA_DQ<29>")
	)
	(arc
		(start 85.248496 -263.362186)
		(mid 85.052556 -263.431232)
		(end 84.84489 -263.424924)
		(width 0.088646)
		(layer "In6.Cu")
		(net "M_C_CPU1_SA_DQ<29>")
	)
	(arc
		(start 96.143826 -263.628886)
		(mid 96.082734 -263.474602)
		(end 95.960946 -263.361932)
		(width 0.088646)
		(layer "In6.Cu")
		(net "M_C_CPU1_SA_DQ<29>")
	)
	(arc
		(start 92.201746 -263.361932)
		(mid 92.017792 -263.311803)
		(end 91.832938 -263.35863)
		(width 0.088646)
		(layer "In6.Cu")
		(net "M_C_CPU1_SA_DQ<29>")
	)
	(arc
		(start 87.502492 -263.362186)
		(mid 87.315294 -263.312043)
		(end 87.128096 -263.362186)
		(width 0.088646)
		(layer "In6.Cu")
		(net "M_C_CPU1_SA_DQ<29>")
	)
	(arc
		(start 90.881454 -263.365488)
		(mid 90.601319 -263.437771)
		(end 90.322146 -263.361932)
		(width 0.088646)
		(layer "In6.Cu")
		(net "M_C_CPU1_SA_DQ<29>")
	)
	(arc
		(start 86.562692 -263.362186)
		(mid 86.375494 -263.312043)
		(end 86.188296 -263.362186)
		(width 0.088646)
		(layer "In6.Cu")
		(net "M_C_CPU1_SA_DQ<29>")
	)
	(arc
		(start 95.580454 -263.365488)
		(mid 95.300319 -263.437771)
		(end 95.021146 -263.361932)
		(width 0.088646)
		(layer "In6.Cu")
		(net "M_C_CPU1_SA_DQ<29>")
	)
	(arc
		(start 89.947496 -263.361932)
		(mid 89.664938 -263.437581)
		(end 89.382346 -263.361932)
		(width 0.088646)
		(layer "In6.Cu")
		(net "M_C_CPU1_SA_DQ<29>")
	)
	(arc
		(start 89.382346 -263.361932)
		(mid 89.197196 -263.311828)
		(end 89.011506 -263.3599)
		(width 0.088646)
		(layer "In6.Cu")
		(net "M_C_CPU1_SA_DQ<29>")
	)
	(arc
		(start 91.821254 -263.365488)
		(mid 91.541119 -263.437771)
		(end 91.261946 -263.361932)
		(width 0.088646)
		(layer "In6.Cu")
		(net "M_C_CPU1_SA_DQ<29>")
	)
	(segment
		(start 95.303594 -263.964674)
		(end 95.303594 -264.50036)
		(width 0.20066)
		(layer "F.Cu")
		(net "M_C_CPU1_SA_DQ<28>")
	)
	(segment
		(start 29.402786 -282.316682)
		(end 30.771846 -282.316682)
		(width 0.20066)
		(layer "F.Cu")
		(net "M_C_CPU1_SA_DQ<28>")
	)
	(segment
		(start 24.562308 -282.316682)
		(end 24.801068 -282.555442)
		(width 0.20066)
		(layer "F.Cu")
		(net "M_C_CPU1_SA_DQ<28>")
	)
	(segment
		(start 95.303848 -263.96442)
		(end 95.303594 -263.964674)
		(width 0.20066)
		(layer "F.Cu")
		(net "M_C_CPU1_SA_DQ<28>")
	)
	(segment
		(start 26.459942 -281.89174)
		(end 28.529026 -281.89174)
		(width 0.1016)
		(layer "F.Cu")
		(net "M_C_CPU1_SA_DQ<28>")
	)
	(segment
		(start 28.977844 -281.89174)
		(end 29.402786 -282.316682)
		(width 0.20066)
		(layer "F.Cu")
		(net "M_C_CPU1_SA_DQ<28>")
	)
	(segment
		(start 24.801068 -282.555442)
		(end 25.259792 -282.555442)
		(width 0.20066)
		(layer "F.Cu")
		(net "M_C_CPU1_SA_DQ<28>")
	)
	(segment
		(start 31.876746 -282.316682)
		(end 30.771846 -282.316682)
		(width 0.20066)
		(layer "F.Cu")
		(net "M_C_CPU1_SA_DQ<28>")
	)
	(segment
		(start 23.228046 -282.316682)
		(end 24.562308 -282.316682)
		(width 0.20066)
		(layer "F.Cu")
		(net "M_C_CPU1_SA_DQ<28>")
	)
	(segment
		(start 25.642062 -281.883612)
		(end 26.20391 -281.883612)
		(width 0.20066)
		(layer "F.Cu")
		(net "M_C_CPU1_SA_DQ<28>")
	)
	(segment
		(start 26.20391 -281.883612)
		(end 26.212038 -281.89174)
		(width 0.101854)
		(layer "F.Cu")
		(net "M_C_CPU1_SA_DQ<28>")
	)
	(segment
		(start 25.259792 -282.555442)
		(end 25.432512 -282.382722)
		(width 0.20066)
		(layer "F.Cu")
		(net "M_C_CPU1_SA_DQ<28>")
	)
	(segment
		(start 25.432512 -282.093162)
		(end 25.642062 -281.883612)
		(width 0.20066)
		(layer "F.Cu")
		(net "M_C_CPU1_SA_DQ<28>")
	)
	(segment
		(start 25.432512 -282.382722)
		(end 25.432512 -282.093162)
		(width 0.20066)
		(layer "F.Cu")
		(net "M_C_CPU1_SA_DQ<28>")
	)
	(segment
		(start 26.212038 -281.89174)
		(end 26.459942 -281.89174)
		(width 0.101854)
		(layer "F.Cu")
		(net "M_C_CPU1_SA_DQ<28>")
	)
	(segment
		(start 28.529026 -281.89174)
		(end 28.977844 -281.89174)
		(width 0.20066)
		(layer "F.Cu")
		(net "M_C_CPU1_SA_DQ<28>")
	)
	(segment
		(start 70.949058 -269.061184)
		(end 66.3956 -273.614642)
		(width 0.18288)
		(layer "In6.Cu")
		(net "M_C_CPU1_SA_DQ<28>")
	)
	(segment
		(start 54.381908 -275.844762)
		(end 52.584858 -277.641812)
		(width 0.18288)
		(layer "In6.Cu")
		(net "M_C_CPU1_SA_DQ<28>")
	)
	(segment
		(start 42.05351 -281.264614)
		(end 40.548306 -281.264614)
		(width 0.18288)
		(layer "In6.Cu")
		(net "M_C_CPU1_SA_DQ<28>")
	)
	(segment
		(start 35.778694 -282.741624)
		(end 34.054542 -282.741624)
		(width 0.18288)
		(layer "In6.Cu")
		(net "M_C_CPU1_SA_DQ<28>")
	)
	(segment
		(start 50.10912 -277.641812)
		(end 49.259236 -278.491696)
		(width 0.18288)
		(layer "In6.Cu")
		(net "M_C_CPU1_SA_DQ<28>")
	)
	(segment
		(start 43.227498 -280.090626)
		(end 42.05351 -281.264614)
		(width 0.18288)
		(layer "In6.Cu")
		(net "M_C_CPU1_SA_DQ<28>")
	)
	(segment
		(start 43.705526 -280.090626)
		(end 43.227498 -280.090626)
		(width 0.18288)
		(layer "In6.Cu")
		(net "M_C_CPU1_SA_DQ<28>")
	)
	(segment
		(start 33.180782 -282.924504)
		(end 32.997902 -282.741624)
		(width 0.18288)
		(layer "In6.Cu")
		(net "M_C_CPU1_SA_DQ<28>")
	)
	(segment
		(start 66.3956 -273.614642)
		(end 65.544446 -273.614642)
		(width 0.18288)
		(layer "In6.Cu")
		(net "M_C_CPU1_SA_DQ<28>")
	)
	(segment
		(start 45.812202 -279.024842)
		(end 44.77131 -279.024842)
		(width 0.18288)
		(layer "In6.Cu")
		(net "M_C_CPU1_SA_DQ<28>")
	)
	(segment
		(start 32.997902 -282.741624)
		(end 32.301688 -282.741624)
		(width 0.18288)
		(layer "In6.Cu")
		(net "M_C_CPU1_SA_DQ<28>")
	)
	(segment
		(start 84.110322 -265.157458)
		(end 84.110322 -265.770614)
		(width 0.088646)
		(layer "In6.Cu")
		(net "M_C_CPU1_SA_DQ<28>")
	)
	(segment
		(start 33.688782 -283.47162)
		(end 33.363662 -283.47162)
		(width 0.18288)
		(layer "In6.Cu")
		(net "M_C_CPU1_SA_DQ<28>")
	)
	(segment
		(start 33.871662 -283.28874)
		(end 33.688782 -283.47162)
		(width 0.18288)
		(layer "In6.Cu")
		(net "M_C_CPU1_SA_DQ<28>")
	)
	(segment
		(start 83.039204 -266.337796)
		(end 81.996788 -266.337796)
		(width 0.18288)
		(layer "In6.Cu")
		(net "M_C_CPU1_SA_DQ<28>")
	)
	(segment
		(start 94.9325 -264.399522)
		(end 94.550992 -264.176002)
		(width 0.088646)
		(layer "In6.Cu")
		(net "M_C_CPU1_SA_DQ<28>")
	)
	(segment
		(start 84.700618 -264.235184)
		(end 84.513674 -264.422128)
		(width 0.088646)
		(layer "In6.Cu")
		(net "M_C_CPU1_SA_DQ<28>")
	)
	(segment
		(start 33.871662 -282.924504)
		(end 33.871662 -283.28874)
		(width 0.18288)
		(layer "In6.Cu")
		(net "M_C_CPU1_SA_DQ<28>")
	)
	(segment
		(start 33.180782 -283.28874)
		(end 33.180782 -282.924504)
		(width 0.18288)
		(layer "In6.Cu")
		(net "M_C_CPU1_SA_DQ<28>")
	)
	(segment
		(start 83.54314 -266.337796)
		(end 83.039204 -266.337796)
		(width 0.088646)
		(layer "In6.Cu")
		(net "M_C_CPU1_SA_DQ<28>")
	)
	(segment
		(start 36.256976 -282.741878)
		(end 35.778948 -282.741878)
		(width 0.18288)
		(layer "In6.Cu")
		(net "M_C_CPU1_SA_DQ<28>")
	)
	(segment
		(start 74.53122 -267.577316)
		(end 70.949058 -269.061184)
		(width 0.18288)
		(layer "In6.Cu")
		(net "M_C_CPU1_SA_DQ<28>")
	)
	(segment
		(start 79.003906 -267.577316)
		(end 74.53122 -267.577316)
		(width 0.18288)
		(layer "In6.Cu")
		(net "M_C_CPU1_SA_DQ<28>")
	)
	(segment
		(start 44.77131 -279.024842)
		(end 43.705526 -280.090626)
		(width 0.18288)
		(layer "In6.Cu")
		(net "M_C_CPU1_SA_DQ<28>")
	)
	(segment
		(start 94.176596 -264.176002)
		(end 94.161864 -264.184638)
		(width 0.088646)
		(layer "In6.Cu")
		(net "M_C_CPU1_SA_DQ<28>")
	)
	(segment
		(start 34.054542 -282.741624)
		(end 33.871662 -282.924504)
		(width 0.18288)
		(layer "In6.Cu")
		(net "M_C_CPU1_SA_DQ<28>")
	)
	(segment
		(start 93.236796 -264.176002)
		(end 93.222064 -264.184638)
		(width 0.088646)
		(layer "In6.Cu")
		(net "M_C_CPU1_SA_DQ<28>")
	)
	(segment
		(start 64.110108 -275.04898)
		(end 55.794656 -275.04898)
		(width 0.18288)
		(layer "In6.Cu")
		(net "M_C_CPU1_SA_DQ<28>")
	)
	(segment
		(start 95.303594 -264.50036)
		(end 94.9325 -264.399522)
		(width 0.088646)
		(layer "In6.Cu")
		(net "M_C_CPU1_SA_DQ<28>")
	)
	(segment
		(start 33.363662 -283.47162)
		(end 33.180782 -283.28874)
		(width 0.18288)
		(layer "In6.Cu")
		(net "M_C_CPU1_SA_DQ<28>")
	)
	(segment
		(start 54.998874 -275.844762)
		(end 54.381908 -275.844762)
		(width 0.18288)
		(layer "In6.Cu")
		(net "M_C_CPU1_SA_DQ<28>")
	)
	(segment
		(start 65.544446 -273.614642)
		(end 64.110108 -275.04898)
		(width 0.18288)
		(layer "In6.Cu")
		(net "M_C_CPU1_SA_DQ<28>")
	)
	(segment
		(start 46.345348 -278.491696)
		(end 45.812202 -279.024842)
		(width 0.18288)
		(layer "In6.Cu")
		(net "M_C_CPU1_SA_DQ<28>")
	)
	(segment
		(start 36.25723 -282.741624)
		(end 36.256976 -282.741878)
		(width 0.18288)
		(layer "In6.Cu")
		(net "M_C_CPU1_SA_DQ<28>")
	)
	(segment
		(start 84.513674 -264.422128)
		(end 84.513674 -264.754106)
		(width 0.088646)
		(layer "In6.Cu")
		(net "M_C_CPU1_SA_DQ<28>")
	)
	(segment
		(start 84.110322 -265.770614)
		(end 83.54314 -266.337796)
		(width 0.088646)
		(layer "In6.Cu")
		(net "M_C_CPU1_SA_DQ<28>")
	)
	(segment
		(start 84.513674 -264.754106)
		(end 84.110322 -265.157458)
		(width 0.088646)
		(layer "In6.Cu")
		(net "M_C_CPU1_SA_DQ<28>")
	)
	(segment
		(start 40.548306 -281.264614)
		(end 39.071296 -282.741624)
		(width 0.18288)
		(layer "In6.Cu")
		(net "M_C_CPU1_SA_DQ<28>")
	)
	(segment
		(start 81.996788 -266.337796)
		(end 79.003906 -267.577316)
		(width 0.18288)
		(layer "In6.Cu")
		(net "M_C_CPU1_SA_DQ<28>")
	)
	(segment
		(start 55.794656 -275.04898)
		(end 54.998874 -275.844762)
		(width 0.18288)
		(layer "In6.Cu")
		(net "M_C_CPU1_SA_DQ<28>")
	)
	(segment
		(start 39.071296 -282.741624)
		(end 36.25723 -282.741624)
		(width 0.18288)
		(layer "In6.Cu")
		(net "M_C_CPU1_SA_DQ<28>")
	)
	(segment
		(start 49.259236 -278.491696)
		(end 46.345348 -278.491696)
		(width 0.18288)
		(layer "In6.Cu")
		(net "M_C_CPU1_SA_DQ<28>")
	)
	(segment
		(start 32.301688 -282.741624)
		(end 31.876746 -282.316682)
		(width 0.18288)
		(layer "In6.Cu")
		(net "M_C_CPU1_SA_DQ<28>")
	)
	(segment
		(start 35.778948 -282.741878)
		(end 35.778694 -282.741624)
		(width 0.18288)
		(layer "In6.Cu")
		(net "M_C_CPU1_SA_DQ<28>")
	)
	(segment
		(start 91.35745 -264.176002)
		(end 91.347036 -264.182098)
		(width 0.088646)
		(layer "In6.Cu")
		(net "M_C_CPU1_SA_DQ<28>")
	)
	(segment
		(start 92.296996 -264.176002)
		(end 92.286582 -264.182098)
		(width 0.088646)
		(layer "In6.Cu")
		(net "M_C_CPU1_SA_DQ<28>")
	)
	(segment
		(start 52.584858 -277.641812)
		(end 50.10912 -277.641812)
		(width 0.18288)
		(layer "In6.Cu")
		(net "M_C_CPU1_SA_DQ<28>")
	)
	(arc
		(start 85.152992 -264.176002)
		(mid 84.965794 -264.125859)
		(end 84.778596 -264.176002)
		(width 0.088646)
		(layer "In6.Cu")
		(net "M_C_CPU1_SA_DQ<28>")
	)
	(arc
		(start 93.222064 -264.184638)
		(mid 92.945589 -264.251958)
		(end 92.671392 -264.176002)
		(width 0.088646)
		(layer "In6.Cu")
		(net "M_C_CPU1_SA_DQ<28>")
	)
	(arc
		(start 89.851992 -264.176002)
		(mid 89.664794 -264.125859)
		(end 89.477596 -264.176002)
		(width 0.088646)
		(layer "In6.Cu")
		(net "M_C_CPU1_SA_DQ<28>")
	)
	(arc
		(start 84.778596 -264.176002)
		(mid 84.737666 -264.203035)
		(end 84.700618 -264.235184)
		(width 0.088646)
		(layer "In6.Cu")
		(net "M_C_CPU1_SA_DQ<28>")
	)
	(arc
		(start 88.912192 -264.176002)
		(mid 88.724994 -264.125859)
		(end 88.537796 -264.176002)
		(width 0.088646)
		(layer "In6.Cu")
		(net "M_C_CPU1_SA_DQ<28>")
	)
	(arc
		(start 91.347036 -264.182098)
		(mid 91.068604 -264.251944)
		(end 90.791792 -264.176002)
		(width 0.088646)
		(layer "In6.Cu")
		(net "M_C_CPU1_SA_DQ<28>")
	)
	(arc
		(start 86.092792 -264.176002)
		(mid 85.905594 -264.125859)
		(end 85.718396 -264.176002)
		(width 0.088646)
		(layer "In6.Cu")
		(net "M_C_CPU1_SA_DQ<28>")
	)
	(arc
		(start 87.972392 -264.176002)
		(mid 87.785194 -264.125859)
		(end 87.597996 -264.176002)
		(width 0.088646)
		(layer "In6.Cu")
		(net "M_C_CPU1_SA_DQ<28>")
	)
	(arc
		(start 92.671392 -264.176002)
		(mid 92.484194 -264.125859)
		(end 92.296996 -264.176002)
		(width 0.088646)
		(layer "In6.Cu")
		(net "M_C_CPU1_SA_DQ<28>")
	)
	(arc
		(start 90.791792 -264.176002)
		(mid 90.604594 -264.125859)
		(end 90.417396 -264.176002)
		(width 0.088646)
		(layer "In6.Cu")
		(net "M_C_CPU1_SA_DQ<28>")
	)
	(arc
		(start 94.161864 -264.184638)
		(mid 93.885389 -264.251958)
		(end 93.611192 -264.176002)
		(width 0.088646)
		(layer "In6.Cu")
		(net "M_C_CPU1_SA_DQ<28>")
	)
	(arc
		(start 86.658196 -264.176002)
		(mid 86.375494 -264.251778)
		(end 86.092792 -264.176002)
		(width 0.088646)
		(layer "In6.Cu")
		(net "M_C_CPU1_SA_DQ<28>")
	)
	(arc
		(start 87.032592 -264.176002)
		(mid 86.845394 -264.125859)
		(end 86.658196 -264.176002)
		(width 0.088646)
		(layer "In6.Cu")
		(net "M_C_CPU1_SA_DQ<28>")
	)
	(arc
		(start 88.537796 -264.176002)
		(mid 88.255094 -264.251778)
		(end 87.972392 -264.176002)
		(width 0.088646)
		(layer "In6.Cu")
		(net "M_C_CPU1_SA_DQ<28>")
	)
	(arc
		(start 87.597996 -264.176002)
		(mid 87.315294 -264.251778)
		(end 87.032592 -264.176002)
		(width 0.088646)
		(layer "In6.Cu")
		(net "M_C_CPU1_SA_DQ<28>")
	)
	(arc
		(start 90.417396 -264.176002)
		(mid 90.134694 -264.251778)
		(end 89.851992 -264.176002)
		(width 0.088646)
		(layer "In6.Cu")
		(net "M_C_CPU1_SA_DQ<28>")
	)
	(arc
		(start 89.477596 -264.176002)
		(mid 89.194894 -264.251778)
		(end 88.912192 -264.176002)
		(width 0.088646)
		(layer "In6.Cu")
		(net "M_C_CPU1_SA_DQ<28>")
	)
	(arc
		(start 94.550992 -264.176002)
		(mid 94.363794 -264.125859)
		(end 94.176596 -264.176002)
		(width 0.088646)
		(layer "In6.Cu")
		(net "M_C_CPU1_SA_DQ<28>")
	)
	(arc
		(start 85.718396 -264.176002)
		(mid 85.435694 -264.251778)
		(end 85.152992 -264.176002)
		(width 0.088646)
		(layer "In6.Cu")
		(net "M_C_CPU1_SA_DQ<28>")
	)
	(arc
		(start 93.611192 -264.176002)
		(mid 93.423994 -264.125859)
		(end 93.236796 -264.176002)
		(width 0.088646)
		(layer "In6.Cu")
		(net "M_C_CPU1_SA_DQ<28>")
	)
	(arc
		(start 92.286582 -264.182098)
		(mid 92.008404 -264.251821)
		(end 91.731846 -264.176002)
		(width 0.088646)
		(layer "In6.Cu")
		(net "M_C_CPU1_SA_DQ<28>")
	)
	(arc
		(start 91.731846 -264.176002)
		(mid 91.544648 -264.125859)
		(end 91.35745 -264.176002)
		(width 0.088646)
		(layer "In6.Cu")
		(net "M_C_CPU1_SA_DQ<28>")
	)
	(segment
		(start 29.025342 -285.716726)
		(end 29.151326 -285.84271)
		(width 0.20066)
		(layer "F.Cu")
		(net "M_C_CPU1_SA_DQ<27>")
	)
	(segment
		(start 97.183194 -266.128246)
		(end 97.183194 -265.592306)
		(width 0.20066)
		(layer "F.Cu")
		(net "M_C_CPU1_SA_DQ<27>")
	)
	(segment
		(start 32.51708 -286.141668)
		(end 32.666178 -285.99257)
		(width 0.20066)
		(layer "F.Cu")
		(net "M_C_CPU1_SA_DQ<27>")
	)
	(segment
		(start 32.666178 -285.99257)
		(end 32.666178 -285.840932)
		(width 0.20066)
		(layer "F.Cu")
		(net "M_C_CPU1_SA_DQ<27>")
	)
	(segment
		(start 27.328114 -285.716726)
		(end 29.025342 -285.716726)
		(width 0.20066)
		(layer "F.Cu")
		(net "M_C_CPU1_SA_DQ<27>")
	)
	(segment
		(start 29.647642 -286.155892)
		(end 29.661866 -286.141668)
		(width 0.101854)
		(layer "F.Cu")
		(net "M_C_CPU1_SA_DQ<27>")
	)
	(segment
		(start 29.661866 -286.141668)
		(end 29.899864 -286.141668)
		(width 0.101854)
		(layer "F.Cu")
		(net "M_C_CPU1_SA_DQ<27>")
	)
	(segment
		(start 29.151326 -286.013398)
		(end 29.29382 -286.155892)
		(width 0.20066)
		(layer "F.Cu")
		(net "M_C_CPU1_SA_DQ<27>")
	)
	(segment
		(start 32.666178 -285.840932)
		(end 32.794702 -285.712408)
		(width 0.20066)
		(layer "F.Cu")
		(net "M_C_CPU1_SA_DQ<27>")
	)
	(segment
		(start 97.183194 -265.592306)
		(end 97.183448 -265.592306)
		(width 0.20066)
		(layer "F.Cu")
		(net "M_C_CPU1_SA_DQ<27>")
	)
	(segment
		(start 29.899864 -286.141668)
		(end 31.972758 -286.141668)
		(width 0.1016)
		(layer "F.Cu")
		(net "M_C_CPU1_SA_DQ<27>")
	)
	(segment
		(start 32.794702 -285.712408)
		(end 33.189926 -285.712408)
		(width 0.20066)
		(layer "F.Cu")
		(net "M_C_CPU1_SA_DQ<27>")
	)
	(segment
		(start 31.972758 -286.141668)
		(end 32.51708 -286.141668)
		(width 0.20066)
		(layer "F.Cu")
		(net "M_C_CPU1_SA_DQ<27>")
	)
	(segment
		(start 33.189926 -285.712408)
		(end 33.401762 -285.924244)
		(width 0.20066)
		(layer "F.Cu")
		(net "M_C_CPU1_SA_DQ<27>")
	)
	(segment
		(start 29.29382 -286.155892)
		(end 29.647642 -286.155892)
		(width 0.20066)
		(layer "F.Cu")
		(net "M_C_CPU1_SA_DQ<27>")
	)
	(segment
		(start 35.976814 -285.716726)
		(end 34.871914 -285.716726)
		(width 0.20066)
		(layer "F.Cu")
		(net "M_C_CPU1_SA_DQ<27>")
	)
	(segment
		(start 33.401762 -285.924244)
		(end 33.848294 -285.924244)
		(width 0.20066)
		(layer "F.Cu")
		(net "M_C_CPU1_SA_DQ<27>")
	)
	(segment
		(start 29.151326 -285.84271)
		(end 29.151326 -286.013398)
		(width 0.20066)
		(layer "F.Cu")
		(net "M_C_CPU1_SA_DQ<27>")
	)
	(segment
		(start 33.848294 -285.924244)
		(end 34.055812 -285.716726)
		(width 0.20066)
		(layer "F.Cu")
		(net "M_C_CPU1_SA_DQ<27>")
	)
	(segment
		(start 34.055812 -285.716726)
		(end 34.871914 -285.716726)
		(width 0.20066)
		(layer "F.Cu")
		(net "M_C_CPU1_SA_DQ<27>")
	)
	(segment
		(start 82.396076 -268.479524)
		(end 71.981822 -272.792444)
		(width 0.18288)
		(layer "In6.Cu")
		(net "M_C_CPU1_SA_DQ<27>")
	)
	(segment
		(start 84.565998 -267.356082)
		(end 84.450682 -267.471398)
		(width 0.088646)
		(layer "In6.Cu")
		(net "M_C_CPU1_SA_DQ<27>")
	)
	(segment
		(start 49.688496 -282.741624)
		(end 46.438312 -282.741624)
		(width 0.18288)
		(layer "In6.Cu")
		(net "M_C_CPU1_SA_DQ<27>")
	)
	(segment
		(start 67.060318 -277.713948)
		(end 65.43929 -277.713948)
		(width 0.18288)
		(layer "In6.Cu")
		(net "M_C_CPU1_SA_DQ<27>")
	)
	(segment
		(start 53.552852 -281.273504)
		(end 53.227732 -281.273504)
		(width 0.18288)
		(layer "In6.Cu")
		(net "M_C_CPU1_SA_DQ<27>")
	)
	(segment
		(start 37.998146 -285.529528)
		(end 37.815266 -285.712408)
		(width 0.18288)
		(layer "In6.Cu")
		(net "M_C_CPU1_SA_DQ<27>")
	)
	(segment
		(start 60.408058 -278.42591)
		(end 60.408058 -279.158446)
		(width 0.18288)
		(layer "In6.Cu")
		(net "M_C_CPU1_SA_DQ<27>")
	)
	(segment
		(start 94.856554 -266.055602)
		(end 94.828106 -266.124436)
		(width 0.088646)
		(layer "In6.Cu")
		(net "M_C_CPU1_SA_DQ<27>")
	)
	(segment
		(start 45.379132 -283.800804)
		(end 43.222926 -283.800804)
		(width 0.18288)
		(layer "In6.Cu")
		(net "M_C_CPU1_SA_DQ<27>")
	)
	(segment
		(start 92.296996 -266.45235)
		(end 92.282264 -266.443714)
		(width 0.088646)
		(layer "In6.Cu")
		(net "M_C_CPU1_SA_DQ<27>")
	)
	(segment
		(start 56.967882 -279.341326)
		(end 55.34152 -280.967688)
		(width 0.18288)
		(layer "In6.Cu")
		(net "M_C_CPU1_SA_DQ<27>")
	)
	(segment
		(start 38.506146 -285.712408)
		(end 38.323266 -285.529528)
		(width 0.18288)
		(layer "In6.Cu")
		(net "M_C_CPU1_SA_DQ<27>")
	)
	(segment
		(start 36.491926 -286.231838)
		(end 35.976814 -285.716726)
		(width 0.18288)
		(layer "In6.Cu")
		(net "M_C_CPU1_SA_DQ<27>")
	)
	(segment
		(start 53.044852 -281.70886)
		(end 52.861972 -281.89174)
		(width 0.18288)
		(layer "In6.Cu")
		(net "M_C_CPU1_SA_DQ<27>")
	)
	(segment
		(start 38.323266 -285.529528)
		(end 37.998146 -285.529528)
		(width 0.18288)
		(layer "In6.Cu")
		(net "M_C_CPU1_SA_DQ<27>")
	)
	(segment
		(start 60.590938 -278.24303)
		(end 60.408058 -278.42591)
		(width 0.18288)
		(layer "In6.Cu")
		(net "M_C_CPU1_SA_DQ<27>")
	)
	(segment
		(start 94.682564 -266.376404)
		(end 94.550992 -266.45235)
		(width 0.088646)
		(layer "In6.Cu")
		(net "M_C_CPU1_SA_DQ<27>")
	)
	(segment
		(start 84.450682 -267.471398)
		(end 84.450682 -267.913612)
		(width 0.088646)
		(layer "In6.Cu")
		(net "M_C_CPU1_SA_DQ<27>")
	)
	(segment
		(start 84.870544 -266.931902)
		(end 84.870544 -266.941808)
		(width 0.088646)
		(layer "In6.Cu")
		(net "M_C_CPU1_SA_DQ<27>")
	)
	(segment
		(start 54.700932 -281.89174)
		(end 53.918612 -281.89174)
		(width 0.18288)
		(layer "In6.Cu")
		(net "M_C_CPU1_SA_DQ<27>")
	)
	(segment
		(start 41.691052 -285.332678)
		(end 40.647874 -285.332678)
		(width 0.18288)
		(layer "In6.Cu")
		(net "M_C_CPU1_SA_DQ<27>")
	)
	(segment
		(start 53.918612 -281.89174)
		(end 53.735732 -281.70886)
		(width 0.18288)
		(layer "In6.Cu")
		(net "M_C_CPU1_SA_DQ<27>")
	)
	(segment
		(start 60.916058 -278.24303)
		(end 60.590938 -278.24303)
		(width 0.18288)
		(layer "In6.Cu")
		(net "M_C_CPU1_SA_DQ<27>")
	)
	(segment
		(start 94.176596 -266.45235)
		(end 94.161864 -266.443714)
		(width 0.088646)
		(layer "In6.Cu")
		(net "M_C_CPU1_SA_DQ<27>")
	)
	(segment
		(start 55.34152 -281.251152)
		(end 54.700932 -281.89174)
		(width 0.18288)
		(layer "In6.Cu")
		(net "M_C_CPU1_SA_DQ<27>")
	)
	(segment
		(start 60.408058 -279.158446)
		(end 60.225178 -279.341326)
		(width 0.18288)
		(layer "In6.Cu")
		(net "M_C_CPU1_SA_DQ<27>")
	)
	(segment
		(start 95.496888 -265.806936)
		(end 95.485204 -265.800332)
		(width 0.088646)
		(layer "In6.Cu")
		(net "M_C_CPU1_SA_DQ<27>")
	)
	(segment
		(start 38.689026 -286.231838)
		(end 38.506146 -286.048958)
		(width 0.18288)
		(layer "In6.Cu")
		(net "M_C_CPU1_SA_DQ<27>")
	)
	(segment
		(start 62.507114 -279.341326)
		(end 61.281818 -279.341326)
		(width 0.18288)
		(layer "In6.Cu")
		(net "M_C_CPU1_SA_DQ<27>")
	)
	(segment
		(start 61.281818 -279.341326)
		(end 61.098938 -279.158446)
		(width 0.18288)
		(layer "In6.Cu")
		(net "M_C_CPU1_SA_DQ<27>")
	)
	(segment
		(start 43.222926 -283.800804)
		(end 41.691052 -285.332678)
		(width 0.18288)
		(layer "In6.Cu")
		(net "M_C_CPU1_SA_DQ<27>")
	)
	(segment
		(start 55.34152 -280.967688)
		(end 55.34152 -281.251152)
		(width 0.18288)
		(layer "In6.Cu")
		(net "M_C_CPU1_SA_DQ<27>")
	)
	(segment
		(start 83.039204 -268.479524)
		(end 82.396076 -268.479524)
		(width 0.18288)
		(layer "In6.Cu")
		(net "M_C_CPU1_SA_DQ<27>")
	)
	(segment
		(start 38.506146 -286.048958)
		(end 38.506146 -285.712408)
		(width 0.18288)
		(layer "In6.Cu")
		(net "M_C_CPU1_SA_DQ<27>")
	)
	(segment
		(start 61.098938 -278.42591)
		(end 60.916058 -278.24303)
		(width 0.18288)
		(layer "In6.Cu")
		(net "M_C_CPU1_SA_DQ<27>")
	)
	(segment
		(start 61.098938 -279.158446)
		(end 61.098938 -278.42591)
		(width 0.18288)
		(layer "In6.Cu")
		(net "M_C_CPU1_SA_DQ<27>")
	)
	(segment
		(start 39.748714 -286.231838)
		(end 38.689026 -286.231838)
		(width 0.18288)
		(layer "In6.Cu")
		(net "M_C_CPU1_SA_DQ<27>")
	)
	(segment
		(start 93.236796 -266.45235)
		(end 93.222064 -266.443714)
		(width 0.088646)
		(layer "In6.Cu")
		(net "M_C_CPU1_SA_DQ<27>")
	)
	(segment
		(start 83.88477 -268.479524)
		(end 83.039204 -268.479524)
		(width 0.088646)
		(layer "In6.Cu")
		(net "M_C_CPU1_SA_DQ<27>")
	)
	(segment
		(start 63.383414 -278.465026)
		(end 62.507114 -279.341326)
		(width 0.18288)
		(layer "In6.Cu")
		(net "M_C_CPU1_SA_DQ<27>")
	)
	(segment
		(start 53.735732 -281.70886)
		(end 53.735732 -281.456384)
		(width 0.18288)
		(layer "In6.Cu")
		(net "M_C_CPU1_SA_DQ<27>")
	)
	(segment
		(start 65.43929 -277.713948)
		(end 64.688212 -278.465026)
		(width 0.18288)
		(layer "In6.Cu")
		(net "M_C_CPU1_SA_DQ<27>")
	)
	(segment
		(start 37.632386 -286.231838)
		(end 36.491926 -286.231838)
		(width 0.18288)
		(layer "In6.Cu")
		(net "M_C_CPU1_SA_DQ<27>")
	)
	(segment
		(start 46.438312 -282.741624)
		(end 45.379132 -283.800804)
		(width 0.18288)
		(layer "In6.Cu")
		(net "M_C_CPU1_SA_DQ<27>")
	)
	(segment
		(start 53.735732 -281.456384)
		(end 53.552852 -281.273504)
		(width 0.18288)
		(layer "In6.Cu")
		(net "M_C_CPU1_SA_DQ<27>")
	)
	(segment
		(start 96.849692 -266.040616)
		(end 96.425004 -265.800332)
		(width 0.088646)
		(layer "In6.Cu")
		(net "M_C_CPU1_SA_DQ<27>")
	)
	(segment
		(start 84.450682 -267.913612)
		(end 83.88477 -268.479524)
		(width 0.088646)
		(layer "In6.Cu")
		(net "M_C_CPU1_SA_DQ<27>")
	)
	(segment
		(start 37.815266 -286.048958)
		(end 37.632386 -286.231838)
		(width 0.18288)
		(layer "In6.Cu")
		(net "M_C_CPU1_SA_DQ<27>")
	)
	(segment
		(start 60.225178 -279.341326)
		(end 56.967882 -279.341326)
		(width 0.18288)
		(layer "In6.Cu")
		(net "M_C_CPU1_SA_DQ<27>")
	)
	(segment
		(start 52.861972 -281.89174)
		(end 50.53838 -281.89174)
		(width 0.18288)
		(layer "In6.Cu")
		(net "M_C_CPU1_SA_DQ<27>")
	)
	(segment
		(start 71.981822 -272.792444)
		(end 67.060318 -277.713948)
		(width 0.18288)
		(layer "In6.Cu")
		(net "M_C_CPU1_SA_DQ<27>")
	)
	(segment
		(start 64.688212 -278.465026)
		(end 63.383414 -278.465026)
		(width 0.18288)
		(layer "In6.Cu")
		(net "M_C_CPU1_SA_DQ<27>")
	)
	(segment
		(start 40.647874 -285.332678)
		(end 39.748714 -286.231838)
		(width 0.18288)
		(layer "In6.Cu")
		(net "M_C_CPU1_SA_DQ<27>")
	)
	(segment
		(start 53.044852 -281.456384)
		(end 53.044852 -281.70886)
		(width 0.18288)
		(layer "In6.Cu")
		(net "M_C_CPU1_SA_DQ<27>")
	)
	(segment
		(start 53.227732 -281.273504)
		(end 53.044852 -281.456384)
		(width 0.18288)
		(layer "In6.Cu")
		(net "M_C_CPU1_SA_DQ<27>")
	)
	(segment
		(start 37.815266 -285.712408)
		(end 37.815266 -286.048958)
		(width 0.18288)
		(layer "In6.Cu")
		(net "M_C_CPU1_SA_DQ<27>")
	)
	(segment
		(start 50.53838 -281.89174)
		(end 49.688496 -282.741624)
		(width 0.18288)
		(layer "In6.Cu")
		(net "M_C_CPU1_SA_DQ<27>")
	)
	(arc
		(start 87.032592 -266.45235)
		(mid 86.845394 -266.502527)
		(end 86.658196 -266.45235)
		(width 0.088646)
		(layer "In6.Cu")
		(net "M_C_CPU1_SA_DQ<27>")
	)
	(arc
		(start 91.357196 -266.45235)
		(mid 91.074494 -266.376574)
		(end 90.791792 -266.45235)
		(width 0.088646)
		(layer "In6.Cu")
		(net "M_C_CPU1_SA_DQ<27>")
	)
	(arc
		(start 96.425004 -265.800332)
		(mid 96.240149 -265.753382)
		(end 96.056196 -265.803634)
		(width 0.088646)
		(layer "In6.Cu")
		(net "M_C_CPU1_SA_DQ<27>")
	)
	(arc
		(start 84.691982 -267.261086)
		(mid 84.625658 -267.304166)
		(end 84.565998 -267.356082)
		(width 0.088646)
		(layer "In6.Cu")
		(net "M_C_CPU1_SA_DQ<27>")
	)
	(arc
		(start 88.912192 -266.45235)
		(mid 88.724994 -266.502527)
		(end 88.537796 -266.45235)
		(width 0.088646)
		(layer "In6.Cu")
		(net "M_C_CPU1_SA_DQ<27>")
	)
	(arc
		(start 85.152992 -266.45235)
		(mid 84.948657 -266.654955)
		(end 84.870544 -266.931902)
		(width 0.088646)
		(layer "In6.Cu")
		(net "M_C_CPU1_SA_DQ<27>")
	)
	(arc
		(start 89.477596 -266.45235)
		(mid 89.194894 -266.376574)
		(end 88.912192 -266.45235)
		(width 0.088646)
		(layer "In6.Cu")
		(net "M_C_CPU1_SA_DQ<27>")
	)
	(arc
		(start 92.671392 -266.45235)
		(mid 92.484194 -266.502527)
		(end 92.296996 -266.45235)
		(width 0.088646)
		(layer "In6.Cu")
		(net "M_C_CPU1_SA_DQ<27>")
	)
	(arc
		(start 94.928944 -265.947398)
		(mid 94.887419 -265.997935)
		(end 94.856554 -266.055602)
		(width 0.088646)
		(layer "In6.Cu")
		(net "M_C_CPU1_SA_DQ<27>")
	)
	(arc
		(start 93.222064 -266.443714)
		(mid 92.945589 -266.376394)
		(end 92.671392 -266.45235)
		(width 0.088646)
		(layer "In6.Cu")
		(net "M_C_CPU1_SA_DQ<27>")
	)
	(arc
		(start 87.972392 -266.45235)
		(mid 87.785194 -266.502527)
		(end 87.597996 -266.45235)
		(width 0.088646)
		(layer "In6.Cu")
		(net "M_C_CPU1_SA_DQ<27>")
	)
	(arc
		(start 96.056196 -265.803634)
		(mid 95.776993 -265.879274)
		(end 95.496888 -265.806936)
		(width 0.088646)
		(layer "In6.Cu")
		(net "M_C_CPU1_SA_DQ<27>")
	)
	(arc
		(start 86.092792 -266.45235)
		(mid 85.905594 -266.502527)
		(end 85.718396 -266.45235)
		(width 0.088646)
		(layer "In6.Cu")
		(net "M_C_CPU1_SA_DQ<27>")
	)
	(arc
		(start 90.791792 -266.45235)
		(mid 90.604594 -266.502527)
		(end 90.417396 -266.45235)
		(width 0.088646)
		(layer "In6.Cu")
		(net "M_C_CPU1_SA_DQ<27>")
	)
	(arc
		(start 90.417396 -266.45235)
		(mid 90.134694 -266.376574)
		(end 89.851992 -266.45235)
		(width 0.088646)
		(layer "In6.Cu")
		(net "M_C_CPU1_SA_DQ<27>")
	)
	(arc
		(start 91.731592 -266.45235)
		(mid 91.544394 -266.502527)
		(end 91.357196 -266.45235)
		(width 0.088646)
		(layer "In6.Cu")
		(net "M_C_CPU1_SA_DQ<27>")
	)
	(arc
		(start 92.282264 -266.443714)
		(mid 92.005789 -266.376394)
		(end 91.731592 -266.45235)
		(width 0.088646)
		(layer "In6.Cu")
		(net "M_C_CPU1_SA_DQ<27>")
	)
	(arc
		(start 97.183194 -266.128246)
		(mid 97.010779 -266.105996)
		(end 96.849692 -266.040616)
		(width 0.088646)
		(layer "In6.Cu")
		(net "M_C_CPU1_SA_DQ<27>")
	)
	(arc
		(start 95.116396 -265.803634)
		(mid 95.01797 -265.869386)
		(end 94.928944 -265.947398)
		(width 0.088646)
		(layer "In6.Cu")
		(net "M_C_CPU1_SA_DQ<27>")
	)
	(arc
		(start 89.851992 -266.45235)
		(mid 89.664794 -266.502527)
		(end 89.477596 -266.45235)
		(width 0.088646)
		(layer "In6.Cu")
		(net "M_C_CPU1_SA_DQ<27>")
	)
	(arc
		(start 95.485204 -265.800332)
		(mid 95.300349 -265.753382)
		(end 95.116396 -265.803634)
		(width 0.088646)
		(layer "In6.Cu")
		(net "M_C_CPU1_SA_DQ<27>")
	)
	(arc
		(start 85.718396 -266.45235)
		(mid 85.435694 -266.376574)
		(end 85.152992 -266.45235)
		(width 0.088646)
		(layer "In6.Cu")
		(net "M_C_CPU1_SA_DQ<27>")
	)
	(arc
		(start 84.870544 -266.941808)
		(mid 84.822865 -267.124708)
		(end 84.691982 -267.261086)
		(width 0.088646)
		(layer "In6.Cu")
		(net "M_C_CPU1_SA_DQ<27>")
	)
	(arc
		(start 88.537796 -266.45235)
		(mid 88.255094 -266.376574)
		(end 87.972392 -266.45235)
		(width 0.088646)
		(layer "In6.Cu")
		(net "M_C_CPU1_SA_DQ<27>")
	)
	(arc
		(start 86.658196 -266.45235)
		(mid 86.375494 -266.376574)
		(end 86.092792 -266.45235)
		(width 0.088646)
		(layer "In6.Cu")
		(net "M_C_CPU1_SA_DQ<27>")
	)
	(arc
		(start 93.611192 -266.45235)
		(mid 93.423994 -266.502527)
		(end 93.236796 -266.45235)
		(width 0.088646)
		(layer "In6.Cu")
		(net "M_C_CPU1_SA_DQ<27>")
	)
	(arc
		(start 94.161864 -266.443714)
		(mid 93.885389 -266.376394)
		(end 93.611192 -266.45235)
		(width 0.088646)
		(layer "In6.Cu")
		(net "M_C_CPU1_SA_DQ<27>")
	)
	(arc
		(start 87.597996 -266.45235)
		(mid 87.315294 -266.376574)
		(end 87.032592 -266.45235)
		(width 0.088646)
		(layer "In6.Cu")
		(net "M_C_CPU1_SA_DQ<27>")
	)
	(arc
		(start 94.550992 -266.45235)
		(mid 94.363794 -266.502527)
		(end 94.176596 -266.45235)
		(width 0.088646)
		(layer "In6.Cu")
		(net "M_C_CPU1_SA_DQ<27>")
	)
	(arc
		(start 94.828106 -266.124436)
		(mid 94.789102 -266.269921)
		(end 94.682564 -266.376404)
		(width 0.088646)
		(layer "In6.Cu")
		(net "M_C_CPU1_SA_DQ<27>")
	)
	(segment
		(start 96.713294 -266.405868)
		(end 96.713548 -266.406122)
		(width 0.20066)
		(layer "F.Cu")
		(net "M_C_CPU1_SA_DQ<26>")
	)
	(segment
		(start 32.74949 -287.13557)
		(end 32.74949 -287.461198)
		(width 0.20066)
		(layer "F.Cu")
		(net "M_C_CPU1_SA_DQ<26>")
	)
	(segment
		(start 32.74949 -287.461198)
		(end 32.916876 -287.628584)
		(width 0.20066)
		(layer "F.Cu")
		(net "M_C_CPU1_SA_DQ<26>")
	)
	(segment
		(start 28.91028 -286.981646)
		(end 29.647642 -286.981646)
		(width 0.20066)
		(layer "F.Cu")
		(net "M_C_CPU1_SA_DQ<26>")
	)
	(segment
		(start 96.713548 -266.406122)
		(end 96.713548 -266.941808)
		(width 0.20066)
		(layer "F.Cu")
		(net "M_C_CPU1_SA_DQ<26>")
	)
	(segment
		(start 32.916876 -287.628584)
		(end 33.345374 -287.628584)
		(width 0.20066)
		(layer "F.Cu")
		(net "M_C_CPU1_SA_DQ<26>")
	)
	(segment
		(start 32.605726 -286.991806)
		(end 32.74949 -287.13557)
		(width 0.20066)
		(layer "F.Cu")
		(net "M_C_CPU1_SA_DQ<26>")
	)
	(segment
		(start 35.976814 -287.416748)
		(end 34.871914 -287.416748)
		(width 0.20066)
		(layer "F.Cu")
		(net "M_C_CPU1_SA_DQ<26>")
	)
	(segment
		(start 29.657802 -286.991806)
		(end 29.912818 -286.991806)
		(width 0.101854)
		(layer "F.Cu")
		(net "M_C_CPU1_SA_DQ<26>")
	)
	(segment
		(start 29.647642 -286.981646)
		(end 29.657802 -286.991806)
		(width 0.101854)
		(layer "F.Cu")
		(net "M_C_CPU1_SA_DQ<26>")
	)
	(segment
		(start 27.328114 -287.416748)
		(end 28.475178 -287.416748)
		(width 0.20066)
		(layer "F.Cu")
		(net "M_C_CPU1_SA_DQ<26>")
	)
	(segment
		(start 28.475178 -287.416748)
		(end 28.91028 -286.981646)
		(width 0.20066)
		(layer "F.Cu")
		(net "M_C_CPU1_SA_DQ<26>")
	)
	(segment
		(start 31.972758 -286.991806)
		(end 32.605726 -286.991806)
		(width 0.20066)
		(layer "F.Cu")
		(net "M_C_CPU1_SA_DQ<26>")
	)
	(segment
		(start 33.345374 -287.628584)
		(end 33.55721 -287.416748)
		(width 0.20066)
		(layer "F.Cu")
		(net "M_C_CPU1_SA_DQ<26>")
	)
	(segment
		(start 33.55721 -287.416748)
		(end 34.871914 -287.416748)
		(width 0.20066)
		(layer "F.Cu")
		(net "M_C_CPU1_SA_DQ<26>")
	)
	(segment
		(start 29.912818 -286.991806)
		(end 31.972758 -286.991806)
		(width 0.1016)
		(layer "F.Cu")
		(net "M_C_CPU1_SA_DQ<26>")
	)
	(segment
		(start 53.385212 -283.951934)
		(end 53.225192 -284.111954)
		(width 0.18288)
		(layer "In6.Cu")
		(net "M_C_CPU1_SA_DQ<26>")
	)
	(segment
		(start 51.888644 -283.951934)
		(end 51.398932 -284.441646)
		(width 0.18288)
		(layer "In6.Cu")
		(net "M_C_CPU1_SA_DQ<26>")
	)
	(segment
		(start 42.973244 -286.258762)
		(end 42.973244 -286.517334)
		(width 0.18288)
		(layer "In6.Cu")
		(net "M_C_CPU1_SA_DQ<26>")
	)
	(segment
		(start 54.63159 -283.951934)
		(end 53.385212 -283.951934)
		(width 0.18288)
		(layer "In6.Cu")
		(net "M_C_CPU1_SA_DQ<26>")
	)
	(segment
		(start 40.80256 -287.006792)
		(end 39.946326 -287.863026)
		(width 0.18288)
		(layer "In6.Cu")
		(net "M_C_CPU1_SA_DQ<26>")
	)
	(segment
		(start 85.035898 -268.169898)
		(end 83.628992 -269.576804)
		(width 0.088646)
		(layer "In6.Cu")
		(net "M_C_CPU1_SA_DQ<26>")
	)
	(segment
		(start 94.096078 -267.25753)
		(end 94.081346 -267.266166)
		(width 0.088646)
		(layer "In6.Cu")
		(net "M_C_CPU1_SA_DQ<26>")
	)
	(segment
		(start 92.216478 -267.25753)
		(end 92.201746 -267.266166)
		(width 0.088646)
		(layer "In6.Cu")
		(net "M_C_CPU1_SA_DQ<26>")
	)
	(segment
		(start 52.691792 -284.779212)
		(end 52.531772 -284.619192)
		(width 0.18288)
		(layer "In6.Cu")
		(net "M_C_CPU1_SA_DQ<26>")
	)
	(segment
		(start 42.723054 -285.75)
		(end 42.723054 -286.008572)
		(width 0.18288)
		(layer "In6.Cu")
		(net "M_C_CPU1_SA_DQ<26>")
	)
	(segment
		(start 49.239424 -284.441646)
		(end 49.041812 -284.244034)
		(width 0.18288)
		(layer "In6.Cu")
		(net "M_C_CPU1_SA_DQ<26>")
	)
	(segment
		(start 57.122314 -281.760676)
		(end 56.353964 -281.760676)
		(width 0.18288)
		(layer "In6.Cu")
		(net "M_C_CPU1_SA_DQ<26>")
	)
	(segment
		(start 65.552574 -279.475184)
		(end 64.879474 -280.148284)
		(width 0.18288)
		(layer "In6.Cu")
		(net "M_C_CPU1_SA_DQ<26>")
	)
	(segment
		(start 43.21175 -285.519876)
		(end 42.953178 -285.519876)
		(width 0.18288)
		(layer "In6.Cu")
		(net "M_C_CPU1_SA_DQ<26>")
	)
	(segment
		(start 63.307468 -280.148284)
		(end 62.650116 -280.805636)
		(width 0.18288)
		(layer "In6.Cu")
		(net "M_C_CPU1_SA_DQ<26>")
	)
	(segment
		(start 53.065172 -284.779212)
		(end 52.691792 -284.779212)
		(width 0.18288)
		(layer "In6.Cu")
		(net "M_C_CPU1_SA_DQ<26>")
	)
	(segment
		(start 57.750964 -281.132026)
		(end 57.122314 -281.760676)
		(width 0.18288)
		(layer "In6.Cu")
		(net "M_C_CPU1_SA_DQ<26>")
	)
	(segment
		(start 42.953178 -285.519876)
		(end 42.723054 -285.75)
		(width 0.18288)
		(layer "In6.Cu")
		(net "M_C_CPU1_SA_DQ<26>")
	)
	(segment
		(start 93.156278 -267.25753)
		(end 93.141546 -267.266166)
		(width 0.088646)
		(layer "In6.Cu")
		(net "M_C_CPU1_SA_DQ<26>")
	)
	(segment
		(start 43.46194 -285.770066)
		(end 43.21175 -285.519876)
		(width 0.18288)
		(layer "In6.Cu")
		(net "M_C_CPU1_SA_DQ<26>")
	)
	(segment
		(start 53.225192 -284.111954)
		(end 53.225192 -284.619192)
		(width 0.18288)
		(layer "In6.Cu")
		(net "M_C_CPU1_SA_DQ<26>")
	)
	(segment
		(start 44.198794 -285.291784)
		(end 43.720512 -285.770066)
		(width 0.18288)
		(layer "In6.Cu")
		(net "M_C_CPU1_SA_DQ<26>")
	)
	(segment
		(start 43.720512 -285.770066)
		(end 43.46194 -285.770066)
		(width 0.18288)
		(layer "In6.Cu")
		(net "M_C_CPU1_SA_DQ<26>")
	)
	(segment
		(start 42.483786 -287.006792)
		(end 40.80256 -287.006792)
		(width 0.18288)
		(layer "In6.Cu")
		(net "M_C_CPU1_SA_DQ<26>")
	)
	(segment
		(start 55.232808 -282.881832)
		(end 55.232808 -283.350716)
		(width 0.18288)
		(layer "In6.Cu")
		(net "M_C_CPU1_SA_DQ<26>")
	)
	(segment
		(start 39.946326 -287.863026)
		(end 36.423092 -287.863026)
		(width 0.18288)
		(layer "In6.Cu")
		(net "M_C_CPU1_SA_DQ<26>")
	)
	(segment
		(start 85.340444 -267.737336)
		(end 85.340444 -267.755878)
		(width 0.088646)
		(layer "In6.Cu")
		(net "M_C_CPU1_SA_DQ<26>")
	)
	(segment
		(start 66.846196 -279.475184)
		(end 65.552574 -279.475184)
		(width 0.18288)
		(layer "In6.Cu")
		(net "M_C_CPU1_SA_DQ<26>")
	)
	(segment
		(start 42.973244 -286.517334)
		(end 42.483786 -287.006792)
		(width 0.18288)
		(layer "In6.Cu")
		(net "M_C_CPU1_SA_DQ<26>")
	)
	(segment
		(start 83.039204 -269.576804)
		(end 82.354166 -269.576804)
		(width 0.18288)
		(layer "In6.Cu")
		(net "M_C_CPU1_SA_DQ<26>")
	)
	(segment
		(start 52.371752 -283.951934)
		(end 51.888644 -283.951934)
		(width 0.18288)
		(layer "In6.Cu")
		(net "M_C_CPU1_SA_DQ<26>")
	)
	(segment
		(start 52.531772 -284.619192)
		(end 52.531772 -284.111954)
		(width 0.18288)
		(layer "In6.Cu")
		(net "M_C_CPU1_SA_DQ<26>")
	)
	(segment
		(start 47.49927 -285.291784)
		(end 44.198794 -285.291784)
		(width 0.18288)
		(layer "In6.Cu")
		(net "M_C_CPU1_SA_DQ<26>")
	)
	(segment
		(start 96.056196 -266.45235)
		(end 96.041464 -266.443714)
		(width 0.088646)
		(layer "In6.Cu")
		(net "M_C_CPU1_SA_DQ<26>")
	)
	(segment
		(start 49.041812 -284.244034)
		(end 48.54702 -284.244034)
		(width 0.18288)
		(layer "In6.Cu")
		(net "M_C_CPU1_SA_DQ<26>")
	)
	(segment
		(start 95.030036 -267.261086)
		(end 95.021146 -267.266166)
		(width 0.088646)
		(layer "In6.Cu")
		(net "M_C_CPU1_SA_DQ<26>")
	)
	(segment
		(start 36.423092 -287.863026)
		(end 35.976814 -287.416748)
		(width 0.18288)
		(layer "In6.Cu")
		(net "M_C_CPU1_SA_DQ<26>")
	)
	(segment
		(start 82.354166 -269.576804)
		(end 72.782176 -273.539204)
		(width 0.18288)
		(layer "In6.Cu")
		(net "M_C_CPU1_SA_DQ<26>")
	)
	(segment
		(start 83.628992 -269.576804)
		(end 83.039204 -269.576804)
		(width 0.088646)
		(layer "In6.Cu")
		(net "M_C_CPU1_SA_DQ<26>")
	)
	(segment
		(start 51.398932 -284.441646)
		(end 49.239424 -284.441646)
		(width 0.18288)
		(layer "In6.Cu")
		(net "M_C_CPU1_SA_DQ<26>")
	)
	(segment
		(start 56.353964 -281.760676)
		(end 55.232808 -282.881832)
		(width 0.18288)
		(layer "In6.Cu")
		(net "M_C_CPU1_SA_DQ<26>")
	)
	(segment
		(start 96.713548 -266.941808)
		(end 96.086422 -266.469622)
		(width 0.088646)
		(layer "In6.Cu")
		(net "M_C_CPU1_SA_DQ<26>")
	)
	(segment
		(start 96.086422 -266.469622)
		(end 96.056196 -266.45235)
		(width 0.088646)
		(layer "In6.Cu")
		(net "M_C_CPU1_SA_DQ<26>")
	)
	(segment
		(start 52.531772 -284.111954)
		(end 52.371752 -283.951934)
		(width 0.18288)
		(layer "In6.Cu")
		(net "M_C_CPU1_SA_DQ<26>")
	)
	(segment
		(start 55.232808 -283.350716)
		(end 54.63159 -283.951934)
		(width 0.18288)
		(layer "In6.Cu")
		(net "M_C_CPU1_SA_DQ<26>")
	)
	(segment
		(start 72.782176 -273.539204)
		(end 66.846196 -279.475184)
		(width 0.18288)
		(layer "In6.Cu")
		(net "M_C_CPU1_SA_DQ<26>")
	)
	(segment
		(start 62.650116 -280.805636)
		(end 59.623198 -280.805636)
		(width 0.18288)
		(layer "In6.Cu")
		(net "M_C_CPU1_SA_DQ<26>")
	)
	(segment
		(start 42.723054 -286.008572)
		(end 42.973244 -286.258762)
		(width 0.18288)
		(layer "In6.Cu")
		(net "M_C_CPU1_SA_DQ<26>")
	)
	(segment
		(start 89.39276 -267.26007)
		(end 89.382092 -267.266166)
		(width 0.088646)
		(layer "In6.Cu")
		(net "M_C_CPU1_SA_DQ<26>")
	)
	(segment
		(start 48.54702 -284.244034)
		(end 47.49927 -285.291784)
		(width 0.18288)
		(layer "In6.Cu")
		(net "M_C_CPU1_SA_DQ<26>")
	)
	(segment
		(start 59.296808 -281.132026)
		(end 57.750964 -281.132026)
		(width 0.18288)
		(layer "In6.Cu")
		(net "M_C_CPU1_SA_DQ<26>")
	)
	(segment
		(start 90.887296 -267.266166)
		(end 90.872564 -267.25753)
		(width 0.088646)
		(layer "In6.Cu")
		(net "M_C_CPU1_SA_DQ<26>")
	)
	(segment
		(start 53.225192 -284.619192)
		(end 53.065172 -284.779212)
		(width 0.18288)
		(layer "In6.Cu")
		(net "M_C_CPU1_SA_DQ<26>")
	)
	(segment
		(start 59.623198 -280.805636)
		(end 59.296808 -281.132026)
		(width 0.18288)
		(layer "In6.Cu")
		(net "M_C_CPU1_SA_DQ<26>")
	)
	(segment
		(start 95.208598 -266.926314)
		(end 95.208598 -266.941808)
		(width 0.088646)
		(layer "In6.Cu")
		(net "M_C_CPU1_SA_DQ<26>")
	)
	(segment
		(start 91.272106 -267.26007)
		(end 91.261692 -267.266166)
		(width 0.088646)
		(layer "In6.Cu")
		(net "M_C_CPU1_SA_DQ<26>")
	)
	(segment
		(start 64.879474 -280.148284)
		(end 63.307468 -280.148284)
		(width 0.18288)
		(layer "In6.Cu")
		(net "M_C_CPU1_SA_DQ<26>")
	)
	(arc
		(start 93.141546 -267.266166)
		(mid 92.954348 -267.316309)
		(end 92.76715 -267.266166)
		(width 0.088646)
		(layer "In6.Cu")
		(net "M_C_CPU1_SA_DQ<26>")
	)
	(arc
		(start 95.021146 -267.266166)
		(mid 94.833948 -267.316309)
		(end 94.64675 -267.266166)
		(width 0.088646)
		(layer "In6.Cu")
		(net "M_C_CPU1_SA_DQ<26>")
	)
	(arc
		(start 92.201746 -267.266166)
		(mid 92.014548 -267.316309)
		(end 91.82735 -267.266166)
		(width 0.088646)
		(layer "In6.Cu")
		(net "M_C_CPU1_SA_DQ<26>")
	)
	(arc
		(start 88.067896 -267.266166)
		(mid 87.785194 -267.190424)
		(end 87.502492 -267.266166)
		(width 0.088646)
		(layer "In6.Cu")
		(net "M_C_CPU1_SA_DQ<26>")
	)
	(arc
		(start 91.261692 -267.266166)
		(mid 91.074494 -267.316309)
		(end 90.887296 -267.266166)
		(width 0.088646)
		(layer "In6.Cu")
		(net "M_C_CPU1_SA_DQ<26>")
	)
	(arc
		(start 96.041464 -266.443714)
		(mid 95.764989 -266.376394)
		(end 95.490792 -266.45235)
		(width 0.088646)
		(layer "In6.Cu")
		(net "M_C_CPU1_SA_DQ<26>")
	)
	(arc
		(start 91.82735 -267.266166)
		(mid 91.550537 -267.19033)
		(end 91.272106 -267.26007)
		(width 0.088646)
		(layer "In6.Cu")
		(net "M_C_CPU1_SA_DQ<26>")
	)
	(arc
		(start 89.947496 -267.266166)
		(mid 89.670937 -267.190457)
		(end 89.39276 -267.26007)
		(width 0.088646)
		(layer "In6.Cu")
		(net "M_C_CPU1_SA_DQ<26>")
	)
	(arc
		(start 88.442292 -267.266166)
		(mid 88.255094 -267.316309)
		(end 88.067896 -267.266166)
		(width 0.088646)
		(layer "In6.Cu")
		(net "M_C_CPU1_SA_DQ<26>")
	)
	(arc
		(start 94.64675 -267.266166)
		(mid 94.372521 -267.190241)
		(end 94.096078 -267.25753)
		(width 0.088646)
		(layer "In6.Cu")
		(net "M_C_CPU1_SA_DQ<26>")
	)
	(arc
		(start 94.081346 -267.266166)
		(mid 93.894148 -267.316309)
		(end 93.70695 -267.266166)
		(width 0.088646)
		(layer "In6.Cu")
		(net "M_C_CPU1_SA_DQ<26>")
	)
	(arc
		(start 93.70695 -267.266166)
		(mid 93.432721 -267.190241)
		(end 93.156278 -267.25753)
		(width 0.088646)
		(layer "In6.Cu")
		(net "M_C_CPU1_SA_DQ<26>")
	)
	(arc
		(start 86.188296 -267.266166)
		(mid 85.905594 -267.190424)
		(end 85.622892 -267.266166)
		(width 0.088646)
		(layer "In6.Cu")
		(net "M_C_CPU1_SA_DQ<26>")
	)
	(arc
		(start 86.562692 -267.266166)
		(mid 86.375494 -267.316309)
		(end 86.188296 -267.266166)
		(width 0.088646)
		(layer "In6.Cu")
		(net "M_C_CPU1_SA_DQ<26>")
	)
	(arc
		(start 85.161882 -268.075156)
		(mid 85.095578 -268.118122)
		(end 85.035898 -268.169898)
		(width 0.088646)
		(layer "In6.Cu")
		(net "M_C_CPU1_SA_DQ<26>")
	)
	(arc
		(start 95.490792 -266.45235)
		(mid 95.287969 -266.652581)
		(end 95.208598 -266.926314)
		(width 0.088646)
		(layer "In6.Cu")
		(net "M_C_CPU1_SA_DQ<26>")
	)
	(arc
		(start 87.128096 -267.266166)
		(mid 86.845394 -267.190424)
		(end 86.562692 -267.266166)
		(width 0.088646)
		(layer "In6.Cu")
		(net "M_C_CPU1_SA_DQ<26>")
	)
	(arc
		(start 89.382092 -267.266166)
		(mid 89.194894 -267.316309)
		(end 89.007696 -267.266166)
		(width 0.088646)
		(layer "In6.Cu")
		(net "M_C_CPU1_SA_DQ<26>")
	)
	(arc
		(start 90.872564 -267.25753)
		(mid 90.596123 -267.190364)
		(end 90.321892 -267.266166)
		(width 0.088646)
		(layer "In6.Cu")
		(net "M_C_CPU1_SA_DQ<26>")
	)
	(arc
		(start 95.208598 -266.941808)
		(mid 95.160919 -267.124708)
		(end 95.030036 -267.261086)
		(width 0.088646)
		(layer "In6.Cu")
		(net "M_C_CPU1_SA_DQ<26>")
	)
	(arc
		(start 90.321892 -267.266166)
		(mid 90.134694 -267.316309)
		(end 89.947496 -267.266166)
		(width 0.088646)
		(layer "In6.Cu")
		(net "M_C_CPU1_SA_DQ<26>")
	)
	(arc
		(start 87.502492 -267.266166)
		(mid 87.315294 -267.316309)
		(end 87.128096 -267.266166)
		(width 0.088646)
		(layer "In6.Cu")
		(net "M_C_CPU1_SA_DQ<26>")
	)
	(arc
		(start 89.007696 -267.266166)
		(mid 88.724994 -267.190424)
		(end 88.442292 -267.266166)
		(width 0.088646)
		(layer "In6.Cu")
		(net "M_C_CPU1_SA_DQ<26>")
	)
	(arc
		(start 85.340444 -267.755878)
		(mid 85.292765 -267.938778)
		(end 85.161882 -268.075156)
		(width 0.088646)
		(layer "In6.Cu")
		(net "M_C_CPU1_SA_DQ<26>")
	)
	(arc
		(start 92.76715 -267.266166)
		(mid 92.492921 -267.190241)
		(end 92.216478 -267.25753)
		(width 0.088646)
		(layer "In6.Cu")
		(net "M_C_CPU1_SA_DQ<26>")
	)
	(arc
		(start 85.622892 -267.266166)
		(mid 85.420606 -267.465147)
		(end 85.340444 -267.737336)
		(width 0.088646)
		(layer "In6.Cu")
		(net "M_C_CPU1_SA_DQ<26>")
	)
	(segment
		(start 25.595072 -286.132778)
		(end 26.20391 -286.132778)
		(width 0.20066)
		(layer "F.Cu")
		(net "M_C_CPU1_SA_DQ<25>")
	)
	(segment
		(start 28.198318 -286.141668)
		(end 28.529026 -286.141668)
		(width 0.101854)
		(layer "F.Cu")
		(net "M_C_CPU1_SA_DQ<25>")
	)
	(segment
		(start 25.432512 -286.295338)
		(end 25.595072 -286.132778)
		(width 0.20066)
		(layer "F.Cu")
		(net "M_C_CPU1_SA_DQ<25>")
	)
	(segment
		(start 24.773636 -286.777938)
		(end 25.27808 -286.777938)
		(width 0.20066)
		(layer "F.Cu")
		(net "M_C_CPU1_SA_DQ<25>")
	)
	(segment
		(start 31.876746 -286.56661)
		(end 30.771846 -286.56661)
		(width 0.20066)
		(layer "F.Cu")
		(net "M_C_CPU1_SA_DQ<25>")
	)
	(segment
		(start 24.562308 -286.56661)
		(end 24.773636 -286.777938)
		(width 0.20066)
		(layer "F.Cu")
		(net "M_C_CPU1_SA_DQ<25>")
	)
	(segment
		(start 29.13253 -286.56661)
		(end 30.771846 -286.56661)
		(width 0.20066)
		(layer "F.Cu")
		(net "M_C_CPU1_SA_DQ<25>")
	)
	(segment
		(start 23.228046 -286.56661)
		(end 24.562308 -286.56661)
		(width 0.20066)
		(layer "F.Cu")
		(net "M_C_CPU1_SA_DQ<25>")
	)
	(segment
		(start 25.432512 -286.623506)
		(end 25.432512 -286.295338)
		(width 0.20066)
		(layer "F.Cu")
		(net "M_C_CPU1_SA_DQ<25>")
	)
	(segment
		(start 25.27808 -286.777938)
		(end 25.432512 -286.623506)
		(width 0.20066)
		(layer "F.Cu")
		(net "M_C_CPU1_SA_DQ<25>")
	)
	(segment
		(start 26.2128 -286.141668)
		(end 28.198318 -286.141668)
		(width 0.1016)
		(layer "F.Cu")
		(net "M_C_CPU1_SA_DQ<25>")
	)
	(segment
		(start 95.303594 -266.128246)
		(end 95.303594 -265.592306)
		(width 0.20066)
		(layer "F.Cu")
		(net "M_C_CPU1_SA_DQ<25>")
	)
	(segment
		(start 95.303594 -265.592306)
		(end 95.303848 -265.592306)
		(width 0.20066)
		(layer "F.Cu")
		(net "M_C_CPU1_SA_DQ<25>")
	)
	(segment
		(start 28.529026 -286.141668)
		(end 28.707588 -286.141668)
		(width 0.20066)
		(layer "F.Cu")
		(net "M_C_CPU1_SA_DQ<25>")
	)
	(segment
		(start 28.707588 -286.141668)
		(end 29.13253 -286.56661)
		(width 0.20066)
		(layer "F.Cu")
		(net "M_C_CPU1_SA_DQ<25>")
	)
	(segment
		(start 26.20391 -286.132778)
		(end 26.2128 -286.141668)
		(width 0.1016)
		(layer "F.Cu")
		(net "M_C_CPU1_SA_DQ<25>")
	)
	(segment
		(start 45.609002 -284.421072)
		(end 43.347386 -284.421072)
		(width 0.18288)
		(layer "In6.Cu")
		(net "M_C_CPU1_SA_DQ<25>")
	)
	(segment
		(start 33.901888 -287.174686)
		(end 33.901888 -287.421574)
		(width 0.18288)
		(layer "In6.Cu")
		(net "M_C_CPU1_SA_DQ<25>")
	)
	(segment
		(start 92.216478 -266.62634)
		(end 92.201746 -266.617704)
		(width 0.088646)
		(layer "In6.Cu")
		(net "M_C_CPU1_SA_DQ<25>")
	)
	(segment
		(start 46.438312 -283.591762)
		(end 45.609002 -284.421072)
		(width 0.18288)
		(layer "In6.Cu")
		(net "M_C_CPU1_SA_DQ<25>")
	)
	(segment
		(start 33.901888 -287.421574)
		(end 33.719008 -287.604454)
		(width 0.18288)
		(layer "In6.Cu")
		(net "M_C_CPU1_SA_DQ<25>")
	)
	(segment
		(start 40.751506 -285.940246)
		(end 39.699946 -286.991806)
		(width 0.18288)
		(layer "In6.Cu")
		(net "M_C_CPU1_SA_DQ<25>")
	)
	(segment
		(start 94.931484 -266.452858)
		(end 94.64675 -266.61745)
		(width 0.088646)
		(layer "In6.Cu")
		(net "M_C_CPU1_SA_DQ<25>")
	)
	(segment
		(start 94.64675 -266.61745)
		(end 94.64675 -266.617704)
		(width 0.088646)
		(layer "In6.Cu")
		(net "M_C_CPU1_SA_DQ<25>")
	)
	(segment
		(start 35.283648 -287.174686)
		(end 35.283648 -287.421574)
		(width 0.18288)
		(layer "In6.Cu")
		(net "M_C_CPU1_SA_DQ<25>")
	)
	(segment
		(start 91.272106 -266.6238)
		(end 91.261692 -266.617704)
		(width 0.088646)
		(layer "In6.Cu")
		(net "M_C_CPU1_SA_DQ<25>")
	)
	(segment
		(start 34.592768 -287.421574)
		(end 34.592768 -287.174686)
		(width 0.18288)
		(layer "In6.Cu")
		(net "M_C_CPU1_SA_DQ<25>")
	)
	(segment
		(start 64.63538 -279.527254)
		(end 63.038482 -279.527254)
		(width 0.18288)
		(layer "In6.Cu")
		(net "M_C_CPU1_SA_DQ<25>")
	)
	(segment
		(start 33.211008 -287.174686)
		(end 33.028128 -286.991806)
		(width 0.18288)
		(layer "In6.Cu")
		(net "M_C_CPU1_SA_DQ<25>")
	)
	(segment
		(start 50.56378 -282.741878)
		(end 49.713896 -283.591762)
		(width 0.18288)
		(layer "In6.Cu")
		(net "M_C_CPU1_SA_DQ<25>")
	)
	(segment
		(start 33.028128 -286.991806)
		(end 32.301942 -286.991806)
		(width 0.18288)
		(layer "In6.Cu")
		(net "M_C_CPU1_SA_DQ<25>")
	)
	(segment
		(start 34.592768 -287.174686)
		(end 34.409888 -286.991806)
		(width 0.18288)
		(layer "In6.Cu")
		(net "M_C_CPU1_SA_DQ<25>")
	)
	(segment
		(start 33.393888 -287.604454)
		(end 33.211008 -287.421574)
		(width 0.18288)
		(layer "In6.Cu")
		(net "M_C_CPU1_SA_DQ<25>")
	)
	(segment
		(start 49.713896 -283.591762)
		(end 46.438312 -283.591762)
		(width 0.18288)
		(layer "In6.Cu")
		(net "M_C_CPU1_SA_DQ<25>")
	)
	(segment
		(start 33.719008 -287.604454)
		(end 33.393888 -287.604454)
		(width 0.18288)
		(layer "In6.Cu")
		(net "M_C_CPU1_SA_DQ<25>")
	)
	(segment
		(start 39.699946 -286.991806)
		(end 35.466528 -286.991806)
		(width 0.18288)
		(layer "In6.Cu")
		(net "M_C_CPU1_SA_DQ<25>")
	)
	(segment
		(start 85.061044 -266.941808)
		(end 85.061044 -266.96035)
		(width 0.088646)
		(layer "In6.Cu")
		(net "M_C_CPU1_SA_DQ<25>")
	)
	(segment
		(start 56.920638 -281.177746)
		(end 56.207406 -281.177746)
		(width 0.18288)
		(layer "In6.Cu")
		(net "M_C_CPU1_SA_DQ<25>")
	)
	(segment
		(start 41.828212 -285.940246)
		(end 40.751506 -285.940246)
		(width 0.18288)
		(layer "In6.Cu")
		(net "M_C_CPU1_SA_DQ<25>")
	)
	(segment
		(start 57.906412 -280.191972)
		(end 56.920638 -281.177746)
		(width 0.18288)
		(layer "In6.Cu")
		(net "M_C_CPU1_SA_DQ<25>")
	)
	(segment
		(start 63.038482 -279.527254)
		(end 62.373764 -280.191972)
		(width 0.18288)
		(layer "In6.Cu")
		(net "M_C_CPU1_SA_DQ<25>")
	)
	(segment
		(start 85.248496 -266.617704)
		(end 85.234272 -266.625832)
		(width 0.088646)
		(layer "In6.Cu")
		(net "M_C_CPU1_SA_DQ<25>")
	)
	(segment
		(start 72.324214 -273.1897)
		(end 67.08521 -278.428704)
		(width 0.18288)
		(layer "In6.Cu")
		(net "M_C_CPU1_SA_DQ<25>")
	)
	(segment
		(start 95.303594 -266.128246)
		(end 95.30334 -266.128246)
		(width 0.088646)
		(layer "In6.Cu")
		(net "M_C_CPU1_SA_DQ<25>")
	)
	(segment
		(start 84.700618 -268.07541)
		(end 83.699604 -269.076424)
		(width 0.088646)
		(layer "In6.Cu")
		(net "M_C_CPU1_SA_DQ<25>")
	)
	(segment
		(start 94.096078 -266.62634)
		(end 94.081346 -266.617704)
		(width 0.088646)
		(layer "In6.Cu")
		(net "M_C_CPU1_SA_DQ<25>")
	)
	(segment
		(start 54.643274 -282.741878)
		(end 50.56378 -282.741878)
		(width 0.18288)
		(layer "In6.Cu")
		(net "M_C_CPU1_SA_DQ<25>")
	)
	(segment
		(start 32.301942 -286.991806)
		(end 31.876746 -286.56661)
		(width 0.18288)
		(layer "In6.Cu")
		(net "M_C_CPU1_SA_DQ<25>")
	)
	(segment
		(start 35.283648 -287.421574)
		(end 35.100768 -287.604454)
		(width 0.18288)
		(layer "In6.Cu")
		(net "M_C_CPU1_SA_DQ<25>")
	)
	(segment
		(start 65.73393 -278.428704)
		(end 64.63538 -279.527254)
		(width 0.18288)
		(layer "In6.Cu")
		(net "M_C_CPU1_SA_DQ<25>")
	)
	(segment
		(start 33.211008 -287.421574)
		(end 33.211008 -287.174686)
		(width 0.18288)
		(layer "In6.Cu")
		(net "M_C_CPU1_SA_DQ<25>")
	)
	(segment
		(start 84.700618 -267.490702)
		(end 84.700618 -268.07541)
		(width 0.088646)
		(layer "In6.Cu")
		(net "M_C_CPU1_SA_DQ<25>")
	)
	(segment
		(start 62.373764 -280.191972)
		(end 57.906412 -280.191972)
		(width 0.18288)
		(layer "In6.Cu")
		(net "M_C_CPU1_SA_DQ<25>")
	)
	(segment
		(start 34.775648 -287.604454)
		(end 34.592768 -287.421574)
		(width 0.18288)
		(layer "In6.Cu")
		(net "M_C_CPU1_SA_DQ<25>")
	)
	(segment
		(start 67.08521 -278.428704)
		(end 65.73393 -278.428704)
		(width 0.18288)
		(layer "In6.Cu")
		(net "M_C_CPU1_SA_DQ<25>")
	)
	(segment
		(start 35.466528 -286.991806)
		(end 35.283648 -287.174686)
		(width 0.18288)
		(layer "In6.Cu")
		(net "M_C_CPU1_SA_DQ<25>")
	)
	(segment
		(start 83.039204 -269.076424)
		(end 82.26044 -269.076424)
		(width 0.18288)
		(layer "In6.Cu")
		(net "M_C_CPU1_SA_DQ<25>")
	)
	(segment
		(start 34.084768 -286.991806)
		(end 33.901888 -287.174686)
		(width 0.18288)
		(layer "In6.Cu")
		(net "M_C_CPU1_SA_DQ<25>")
	)
	(segment
		(start 82.26044 -269.076424)
		(end 72.324214 -273.1897)
		(width 0.18288)
		(layer "In6.Cu")
		(net "M_C_CPU1_SA_DQ<25>")
	)
	(segment
		(start 56.207406 -281.177746)
		(end 54.643274 -282.741878)
		(width 0.18288)
		(layer "In6.Cu")
		(net "M_C_CPU1_SA_DQ<25>")
	)
	(segment
		(start 34.409888 -286.991806)
		(end 34.084768 -286.991806)
		(width 0.18288)
		(layer "In6.Cu")
		(net "M_C_CPU1_SA_DQ<25>")
	)
	(segment
		(start 93.156278 -266.62634)
		(end 93.141546 -266.617704)
		(width 0.088646)
		(layer "In6.Cu")
		(net "M_C_CPU1_SA_DQ<25>")
	)
	(segment
		(start 83.699604 -269.076424)
		(end 83.039204 -269.076424)
		(width 0.088646)
		(layer "In6.Cu")
		(net "M_C_CPU1_SA_DQ<25>")
	)
	(segment
		(start 35.100768 -287.604454)
		(end 34.775648 -287.604454)
		(width 0.18288)
		(layer "In6.Cu")
		(net "M_C_CPU1_SA_DQ<25>")
	)
	(segment
		(start 95.30334 -266.128246)
		(end 95.134938 -266.296648)
		(width 0.088646)
		(layer "In6.Cu")
		(net "M_C_CPU1_SA_DQ<25>")
	)
	(segment
		(start 43.347386 -284.421072)
		(end 41.828212 -285.940246)
		(width 0.18288)
		(layer "In6.Cu")
		(net "M_C_CPU1_SA_DQ<25>")
	)
	(arc
		(start 86.562692 -266.617704)
		(mid 86.375494 -266.567527)
		(end 86.188296 -266.617704)
		(width 0.088646)
		(layer "In6.Cu")
		(net "M_C_CPU1_SA_DQ<25>")
	)
	(arc
		(start 85.061044 -266.96035)
		(mid 84.980882 -267.232539)
		(end 84.778596 -267.43152)
		(width 0.088646)
		(layer "In6.Cu")
		(net "M_C_CPU1_SA_DQ<25>")
	)
	(arc
		(start 91.261692 -266.617704)
		(mid 91.074494 -266.567527)
		(end 90.887296 -266.617704)
		(width 0.088646)
		(layer "In6.Cu")
		(net "M_C_CPU1_SA_DQ<25>")
	)
	(arc
		(start 89.947496 -266.617704)
		(mid 89.664794 -266.69348)
		(end 89.382092 -266.617704)
		(width 0.088646)
		(layer "In6.Cu")
		(net "M_C_CPU1_SA_DQ<25>")
	)
	(arc
		(start 90.887296 -266.617704)
		(mid 90.604594 -266.69348)
		(end 90.321892 -266.617704)
		(width 0.088646)
		(layer "In6.Cu")
		(net "M_C_CPU1_SA_DQ<25>")
	)
	(arc
		(start 90.321892 -266.617704)
		(mid 90.134694 -266.567527)
		(end 89.947496 -266.617704)
		(width 0.088646)
		(layer "In6.Cu")
		(net "M_C_CPU1_SA_DQ<25>")
	)
	(arc
		(start 85.622892 -266.617704)
		(mid 85.435694 -266.567527)
		(end 85.248496 -266.617704)
		(width 0.088646)
		(layer "In6.Cu")
		(net "M_C_CPU1_SA_DQ<25>")
	)
	(arc
		(start 92.201746 -266.617704)
		(mid 92.014548 -266.567527)
		(end 91.82735 -266.617704)
		(width 0.088646)
		(layer "In6.Cu")
		(net "M_C_CPU1_SA_DQ<25>")
	)
	(arc
		(start 91.82735 -266.617704)
		(mid 91.550537 -266.693574)
		(end 91.272106 -266.6238)
		(width 0.088646)
		(layer "In6.Cu")
		(net "M_C_CPU1_SA_DQ<25>")
	)
	(arc
		(start 87.128096 -266.617704)
		(mid 86.845394 -266.69348)
		(end 86.562692 -266.617704)
		(width 0.088646)
		(layer "In6.Cu")
		(net "M_C_CPU1_SA_DQ<25>")
	)
	(arc
		(start 93.70695 -266.617704)
		(mid 93.432751 -266.693539)
		(end 93.156278 -266.62634)
		(width 0.088646)
		(layer "In6.Cu")
		(net "M_C_CPU1_SA_DQ<25>")
	)
	(arc
		(start 89.382092 -266.617704)
		(mid 89.194894 -266.567527)
		(end 89.007696 -266.617704)
		(width 0.088646)
		(layer "In6.Cu")
		(net "M_C_CPU1_SA_DQ<25>")
	)
	(arc
		(start 93.141546 -266.617704)
		(mid 92.954348 -266.567527)
		(end 92.76715 -266.617704)
		(width 0.088646)
		(layer "In6.Cu")
		(net "M_C_CPU1_SA_DQ<25>")
	)
	(arc
		(start 89.007696 -266.617704)
		(mid 88.724994 -266.69348)
		(end 88.442292 -266.617704)
		(width 0.088646)
		(layer "In6.Cu")
		(net "M_C_CPU1_SA_DQ<25>")
	)
	(arc
		(start 95.134938 -266.296648)
		(mid 95.038317 -266.381402)
		(end 94.931484 -266.452858)
		(width 0.088646)
		(layer "In6.Cu")
		(net "M_C_CPU1_SA_DQ<25>")
	)
	(arc
		(start 92.76715 -266.617704)
		(mid 92.492951 -266.693539)
		(end 92.216478 -266.62634)
		(width 0.088646)
		(layer "In6.Cu")
		(net "M_C_CPU1_SA_DQ<25>")
	)
	(arc
		(start 85.234272 -266.625832)
		(mid 85.107229 -266.761648)
		(end 85.061044 -266.941808)
		(width 0.088646)
		(layer "In6.Cu")
		(net "M_C_CPU1_SA_DQ<25>")
	)
	(arc
		(start 88.067896 -266.617704)
		(mid 87.785194 -266.69348)
		(end 87.502492 -266.617704)
		(width 0.088646)
		(layer "In6.Cu")
		(net "M_C_CPU1_SA_DQ<25>")
	)
	(arc
		(start 88.442292 -266.617704)
		(mid 88.255094 -266.567527)
		(end 88.067896 -266.617704)
		(width 0.088646)
		(layer "In6.Cu")
		(net "M_C_CPU1_SA_DQ<25>")
	)
	(arc
		(start 84.778596 -267.43152)
		(mid 84.737666 -267.458553)
		(end 84.700618 -267.490702)
		(width 0.088646)
		(layer "In6.Cu")
		(net "M_C_CPU1_SA_DQ<25>")
	)
	(arc
		(start 87.502492 -266.617704)
		(mid 87.315294 -266.567527)
		(end 87.128096 -266.617704)
		(width 0.088646)
		(layer "In6.Cu")
		(net "M_C_CPU1_SA_DQ<25>")
	)
	(arc
		(start 94.081346 -266.617704)
		(mid 93.894148 -266.567527)
		(end 93.70695 -266.617704)
		(width 0.088646)
		(layer "In6.Cu")
		(net "M_C_CPU1_SA_DQ<25>")
	)
	(arc
		(start 94.64675 -266.617704)
		(mid 94.372551 -266.693539)
		(end 94.096078 -266.62634)
		(width 0.088646)
		(layer "In6.Cu")
		(net "M_C_CPU1_SA_DQ<25>")
	)
	(arc
		(start 86.188296 -266.617704)
		(mid 85.905594 -266.69348)
		(end 85.622892 -266.617704)
		(width 0.088646)
		(layer "In6.Cu")
		(net "M_C_CPU1_SA_DQ<25>")
	)
	(segment
		(start 31.876746 -288.266632)
		(end 30.771846 -288.266632)
		(width 0.20066)
		(layer "F.Cu")
		(net "M_C_CPU1_SA_DQ<24>")
	)
	(segment
		(start 28.977844 -287.84169)
		(end 29.402786 -288.266632)
		(width 0.20066)
		(layer "F.Cu")
		(net "M_C_CPU1_SA_DQ<24>")
	)
	(segment
		(start 95.773494 -266.405868)
		(end 95.773748 -266.406122)
		(width 0.20066)
		(layer "F.Cu")
		(net "M_C_CPU1_SA_DQ<24>")
	)
	(segment
		(start 29.402786 -288.266632)
		(end 30.771846 -288.266632)
		(width 0.20066)
		(layer "F.Cu")
		(net "M_C_CPU1_SA_DQ<24>")
	)
	(segment
		(start 25.432512 -288.043112)
		(end 25.642062 -287.833562)
		(width 0.20066)
		(layer "F.Cu")
		(net "M_C_CPU1_SA_DQ<24>")
	)
	(segment
		(start 25.642062 -287.833562)
		(end 26.20391 -287.833562)
		(width 0.20066)
		(layer "F.Cu")
		(net "M_C_CPU1_SA_DQ<24>")
	)
	(segment
		(start 28.529026 -287.84169)
		(end 28.977844 -287.84169)
		(width 0.20066)
		(layer "F.Cu")
		(net "M_C_CPU1_SA_DQ<24>")
	)
	(segment
		(start 26.20391 -287.833562)
		(end 26.212038 -287.84169)
		(width 0.101854)
		(layer "F.Cu")
		(net "M_C_CPU1_SA_DQ<24>")
	)
	(segment
		(start 26.212038 -287.84169)
		(end 26.459942 -287.84169)
		(width 0.101854)
		(layer "F.Cu")
		(net "M_C_CPU1_SA_DQ<24>")
	)
	(segment
		(start 26.459942 -287.84169)
		(end 28.529026 -287.84169)
		(width 0.1016)
		(layer "F.Cu")
		(net "M_C_CPU1_SA_DQ<24>")
	)
	(segment
		(start 25.259792 -288.505392)
		(end 25.432512 -288.332672)
		(width 0.20066)
		(layer "F.Cu")
		(net "M_C_CPU1_SA_DQ<24>")
	)
	(segment
		(start 95.773748 -266.406122)
		(end 95.773748 -266.941808)
		(width 0.20066)
		(layer "F.Cu")
		(net "M_C_CPU1_SA_DQ<24>")
	)
	(segment
		(start 25.432512 -288.332672)
		(end 25.432512 -288.043112)
		(width 0.20066)
		(layer "F.Cu")
		(net "M_C_CPU1_SA_DQ<24>")
	)
	(segment
		(start 23.228046 -288.266632)
		(end 24.562308 -288.266632)
		(width 0.20066)
		(layer "F.Cu")
		(net "M_C_CPU1_SA_DQ<24>")
	)
	(segment
		(start 24.562308 -288.266632)
		(end 24.801068 -288.505392)
		(width 0.20066)
		(layer "F.Cu")
		(net "M_C_CPU1_SA_DQ<24>")
	)
	(segment
		(start 24.801068 -288.505392)
		(end 25.259792 -288.505392)
		(width 0.20066)
		(layer "F.Cu")
		(net "M_C_CPU1_SA_DQ<24>")
	)
	(segment
		(start 32.301688 -288.691574)
		(end 31.876746 -288.266632)
		(width 0.18288)
		(layer "In6.Cu")
		(net "M_C_CPU1_SA_DQ<24>")
	)
	(segment
		(start 85.170518 -268.304518)
		(end 83.932014 -269.543022)
		(width 0.088646)
		(layer "In6.Cu")
		(net "M_C_CPU1_SA_DQ<24>")
	)
	(segment
		(start 83.932014 -269.543022)
		(end 83.932014 -269.987268)
		(width 0.088646)
		(layer "In6.Cu")
		(net "M_C_CPU1_SA_DQ<24>")
	)
	(segment
		(start 43.634152 -287.552638)
		(end 41.18483 -287.552638)
		(width 0.18288)
		(layer "In6.Cu")
		(net "M_C_CPU1_SA_DQ<24>")
	)
	(segment
		(start 93.236796 -267.43152)
		(end 93.222064 -267.440156)
		(width 0.088646)
		(layer "In6.Cu")
		(net "M_C_CPU1_SA_DQ<24>")
	)
	(segment
		(start 53.516276 -285.291784)
		(end 50.53838 -285.291784)
		(width 0.18288)
		(layer "In6.Cu")
		(net "M_C_CPU1_SA_DQ<24>")
	)
	(segment
		(start 54.08422 -284.72384)
		(end 53.516276 -285.291784)
		(width 0.18288)
		(layer "In6.Cu")
		(net "M_C_CPU1_SA_DQ<24>")
	)
	(segment
		(start 67.11696 -280.027634)
		(end 65.990724 -280.027634)
		(width 0.18288)
		(layer "In6.Cu")
		(net "M_C_CPU1_SA_DQ<24>")
	)
	(segment
		(start 62.344554 -281.893772)
		(end 57.761632 -281.893772)
		(width 0.18288)
		(layer "In6.Cu")
		(net "M_C_CPU1_SA_DQ<24>")
	)
	(segment
		(start 95.145352 -267.41501)
		(end 95.116396 -267.43152)
		(width 0.088646)
		(layer "In6.Cu")
		(net "M_C_CPU1_SA_DQ<24>")
	)
	(segment
		(start 85.530944 -267.755878)
		(end 85.530944 -267.765784)
		(width 0.088646)
		(layer "In6.Cu")
		(net "M_C_CPU1_SA_DQ<24>")
	)
	(segment
		(start 95.116396 -267.43152)
		(end 95.101664 -267.440156)
		(width 0.088646)
		(layer "In6.Cu")
		(net "M_C_CPU1_SA_DQ<24>")
	)
	(segment
		(start 41.18483 -287.552638)
		(end 40.045894 -288.691574)
		(width 0.18288)
		(layer "In6.Cu")
		(net "M_C_CPU1_SA_DQ<24>")
	)
	(segment
		(start 83.342988 -270.12392)
		(end 82.334862 -270.12392)
		(width 0.18288)
		(layer "In6.Cu")
		(net "M_C_CPU1_SA_DQ<24>")
	)
	(segment
		(start 95.571056 -267.309346)
		(end 95.5675 -267.311632)
		(width 0.088646)
		(layer "In6.Cu")
		(net "M_C_CPU1_SA_DQ<24>")
	)
	(segment
		(start 50.53838 -285.291784)
		(end 49.688496 -286.141668)
		(width 0.18288)
		(layer "In6.Cu")
		(net "M_C_CPU1_SA_DQ<24>")
	)
	(segment
		(start 95.483172 -267.340588)
		(end 95.298514 -267.358876)
		(width 0.088646)
		(layer "In6.Cu")
		(net "M_C_CPU1_SA_DQ<24>")
	)
	(segment
		(start 89.862406 -267.437616)
		(end 89.851992 -267.43152)
		(width 0.088646)
		(layer "In6.Cu")
		(net "M_C_CPU1_SA_DQ<24>")
	)
	(segment
		(start 54.931564 -284.72384)
		(end 54.08422 -284.72384)
		(width 0.18288)
		(layer "In6.Cu")
		(net "M_C_CPU1_SA_DQ<24>")
	)
	(segment
		(start 73.266808 -273.877786)
		(end 67.11696 -280.027634)
		(width 0.18288)
		(layer "In6.Cu")
		(net "M_C_CPU1_SA_DQ<24>")
	)
	(segment
		(start 45.045122 -286.141668)
		(end 43.634152 -287.552638)
		(width 0.18288)
		(layer "In6.Cu")
		(net "M_C_CPU1_SA_DQ<24>")
	)
	(segment
		(start 82.334862 -270.12392)
		(end 73.266808 -273.877786)
		(width 0.18288)
		(layer "In6.Cu")
		(net "M_C_CPU1_SA_DQ<24>")
	)
	(segment
		(start 63.171324 -281.067002)
		(end 62.344554 -281.893772)
		(width 0.18288)
		(layer "In6.Cu")
		(net "M_C_CPU1_SA_DQ<24>")
	)
	(segment
		(start 94.176596 -267.43152)
		(end 94.161864 -267.440156)
		(width 0.088646)
		(layer "In6.Cu")
		(net "M_C_CPU1_SA_DQ<24>")
	)
	(segment
		(start 40.045894 -288.691574)
		(end 32.301688 -288.691574)
		(width 0.18288)
		(layer "In6.Cu")
		(net "M_C_CPU1_SA_DQ<24>")
	)
	(segment
		(start 85.718396 -267.43152)
		(end 85.709506 -267.4366)
		(width 0.088646)
		(layer "In6.Cu")
		(net "M_C_CPU1_SA_DQ<24>")
	)
	(segment
		(start 90.80246 -267.437616)
		(end 90.792046 -267.43152)
		(width 0.088646)
		(layer "In6.Cu")
		(net "M_C_CPU1_SA_DQ<24>")
	)
	(segment
		(start 95.212662 -267.382752)
		(end 95.145352 -267.41501)
		(width 0.088646)
		(layer "In6.Cu")
		(net "M_C_CPU1_SA_DQ<24>")
	)
	(segment
		(start 57.761632 -281.893772)
		(end 54.931564 -284.72384)
		(width 0.18288)
		(layer "In6.Cu")
		(net "M_C_CPU1_SA_DQ<24>")
	)
	(segment
		(start 65.990724 -280.027634)
		(end 64.951356 -281.067002)
		(width 0.18288)
		(layer "In6.Cu")
		(net "M_C_CPU1_SA_DQ<24>")
	)
	(segment
		(start 64.951356 -281.067002)
		(end 63.171324 -281.067002)
		(width 0.18288)
		(layer "In6.Cu")
		(net "M_C_CPU1_SA_DQ<24>")
	)
	(segment
		(start 83.795362 -270.12392)
		(end 83.342988 -270.12392)
		(width 0.088646)
		(layer "In6.Cu")
		(net "M_C_CPU1_SA_DQ<24>")
	)
	(segment
		(start 92.296996 -267.43152)
		(end 92.282264 -267.440156)
		(width 0.088646)
		(layer "In6.Cu")
		(net "M_C_CPU1_SA_DQ<24>")
	)
	(segment
		(start 49.688496 -286.141668)
		(end 45.045122 -286.141668)
		(width 0.18288)
		(layer "In6.Cu")
		(net "M_C_CPU1_SA_DQ<24>")
	)
	(segment
		(start 83.932014 -269.987268)
		(end 83.795362 -270.12392)
		(width 0.088646)
		(layer "In6.Cu")
		(net "M_C_CPU1_SA_DQ<24>")
	)
	(arc
		(start 86.658196 -267.43152)
		(mid 86.375494 -267.507262)
		(end 86.092792 -267.43152)
		(width 0.088646)
		(layer "In6.Cu")
		(net "M_C_CPU1_SA_DQ<24>")
	)
	(arc
		(start 90.41765 -267.43152)
		(mid 90.140837 -267.507356)
		(end 89.862406 -267.437616)
		(width 0.088646)
		(layer "In6.Cu")
		(net "M_C_CPU1_SA_DQ<24>")
	)
	(arc
		(start 85.248496 -268.245336)
		(mid 85.207566 -268.272369)
		(end 85.170518 -268.304518)
		(width 0.088646)
		(layer "In6.Cu")
		(net "M_C_CPU1_SA_DQ<24>")
	)
	(arc
		(start 90.792046 -267.43152)
		(mid 90.604848 -267.381377)
		(end 90.41765 -267.43152)
		(width 0.088646)
		(layer "In6.Cu")
		(net "M_C_CPU1_SA_DQ<24>")
	)
	(arc
		(start 85.709506 -267.4366)
		(mid 85.578592 -267.57296)
		(end 85.530944 -267.755878)
		(width 0.088646)
		(layer "In6.Cu")
		(net "M_C_CPU1_SA_DQ<24>")
	)
	(arc
		(start 88.912192 -267.43152)
		(mid 88.724994 -267.381377)
		(end 88.537796 -267.43152)
		(width 0.088646)
		(layer "In6.Cu")
		(net "M_C_CPU1_SA_DQ<24>")
	)
	(arc
		(start 85.530944 -267.765784)
		(mid 85.452833 -268.042733)
		(end 85.248496 -268.245336)
		(width 0.088646)
		(layer "In6.Cu")
		(net "M_C_CPU1_SA_DQ<24>")
	)
	(arc
		(start 86.092792 -267.43152)
		(mid 85.905594 -267.381377)
		(end 85.718396 -267.43152)
		(width 0.088646)
		(layer "In6.Cu")
		(net "M_C_CPU1_SA_DQ<24>")
	)
	(arc
		(start 93.222064 -267.440156)
		(mid 92.945623 -267.507322)
		(end 92.671392 -267.43152)
		(width 0.088646)
		(layer "In6.Cu")
		(net "M_C_CPU1_SA_DQ<24>")
	)
	(arc
		(start 89.477596 -267.43152)
		(mid 89.194894 -267.507262)
		(end 88.912192 -267.43152)
		(width 0.088646)
		(layer "In6.Cu")
		(net "M_C_CPU1_SA_DQ<24>")
	)
	(arc
		(start 92.671392 -267.43152)
		(mid 92.484194 -267.381377)
		(end 92.296996 -267.43152)
		(width 0.088646)
		(layer "In6.Cu")
		(net "M_C_CPU1_SA_DQ<24>")
	)
	(arc
		(start 95.773748 -266.941808)
		(mid 95.719771 -267.151699)
		(end 95.571056 -267.309346)
		(width 0.088646)
		(layer "In6.Cu")
		(net "M_C_CPU1_SA_DQ<24>")
	)
	(arc
		(start 87.972392 -267.43152)
		(mid 87.785194 -267.381377)
		(end 87.597996 -267.43152)
		(width 0.088646)
		(layer "In6.Cu")
		(net "M_C_CPU1_SA_DQ<24>")
	)
	(arc
		(start 92.282264 -267.440156)
		(mid 92.005823 -267.507322)
		(end 91.731592 -267.43152)
		(width 0.088646)
		(layer "In6.Cu")
		(net "M_C_CPU1_SA_DQ<24>")
	)
	(arc
		(start 87.032592 -267.43152)
		(mid 86.845394 -267.381377)
		(end 86.658196 -267.43152)
		(width 0.088646)
		(layer "In6.Cu")
		(net "M_C_CPU1_SA_DQ<24>")
	)
	(arc
		(start 91.731592 -267.43152)
		(mid 91.544394 -267.381377)
		(end 91.357196 -267.43152)
		(width 0.088646)
		(layer "In6.Cu")
		(net "M_C_CPU1_SA_DQ<24>")
	)
	(arc
		(start 88.537796 -267.43152)
		(mid 88.255094 -267.507262)
		(end 87.972392 -267.43152)
		(width 0.088646)
		(layer "In6.Cu")
		(net "M_C_CPU1_SA_DQ<24>")
	)
	(arc
		(start 95.5675 -267.311632)
		(mid 95.527018 -267.331)
		(end 95.483172 -267.340588)
		(width 0.088646)
		(layer "In6.Cu")
		(net "M_C_CPU1_SA_DQ<24>")
	)
	(arc
		(start 94.161864 -267.440156)
		(mid 93.885423 -267.507322)
		(end 93.611192 -267.43152)
		(width 0.088646)
		(layer "In6.Cu")
		(net "M_C_CPU1_SA_DQ<24>")
	)
	(arc
		(start 91.357196 -267.43152)
		(mid 91.080637 -267.507229)
		(end 90.80246 -267.437616)
		(width 0.088646)
		(layer "In6.Cu")
		(net "M_C_CPU1_SA_DQ<24>")
	)
	(arc
		(start 89.851992 -267.43152)
		(mid 89.664794 -267.381377)
		(end 89.477596 -267.43152)
		(width 0.088646)
		(layer "In6.Cu")
		(net "M_C_CPU1_SA_DQ<24>")
	)
	(arc
		(start 93.611192 -267.43152)
		(mid 93.423994 -267.381377)
		(end 93.236796 -267.43152)
		(width 0.088646)
		(layer "In6.Cu")
		(net "M_C_CPU1_SA_DQ<24>")
	)
	(arc
		(start 95.101664 -267.440156)
		(mid 94.825223 -267.507322)
		(end 94.550992 -267.43152)
		(width 0.088646)
		(layer "In6.Cu")
		(net "M_C_CPU1_SA_DQ<24>")
	)
	(arc
		(start 95.298514 -267.358876)
		(mid 95.254559 -267.367112)
		(end 95.212662 -267.382752)
		(width 0.088646)
		(layer "In6.Cu")
		(net "M_C_CPU1_SA_DQ<24>")
	)
	(arc
		(start 94.550992 -267.43152)
		(mid 94.363794 -267.381377)
		(end 94.176596 -267.43152)
		(width 0.088646)
		(layer "In6.Cu")
		(net "M_C_CPU1_SA_DQ<24>")
	)
	(arc
		(start 87.597996 -267.43152)
		(mid 87.315294 -267.507262)
		(end 87.032592 -267.43152)
		(width 0.088646)
		(layer "In6.Cu")
		(net "M_C_CPU1_SA_DQ<24>")
	)
	(segment
		(start 29.661866 -289.541712)
		(end 29.899864 -289.541712)
		(width 0.101854)
		(layer "F.Cu")
		(net "M_C_CPU1_SA_DQ<23>")
	)
	(segment
		(start 29.29382 -289.555936)
		(end 29.647642 -289.555936)
		(width 0.20066)
		(layer "F.Cu")
		(net "M_C_CPU1_SA_DQ<23>")
	)
	(segment
		(start 29.151326 -289.413442)
		(end 29.29382 -289.555936)
		(width 0.20066)
		(layer "F.Cu")
		(net "M_C_CPU1_SA_DQ<23>")
	)
	(segment
		(start 93.423994 -265.592306)
		(end 93.424248 -265.592306)
		(width 0.20066)
		(layer "F.Cu")
		(net "M_C_CPU1_SA_DQ<23>")
	)
	(segment
		(start 32.666178 -289.392614)
		(end 32.666178 -289.240976)
		(width 0.20066)
		(layer "F.Cu")
		(net "M_C_CPU1_SA_DQ<23>")
	)
	(segment
		(start 35.976814 -289.11677)
		(end 34.871914 -289.11677)
		(width 0.20066)
		(layer "F.Cu")
		(net "M_C_CPU1_SA_DQ<23>")
	)
	(segment
		(start 27.328114 -289.11677)
		(end 29.025342 -289.11677)
		(width 0.20066)
		(layer "F.Cu")
		(net "M_C_CPU1_SA_DQ<23>")
	)
	(segment
		(start 32.666178 -289.240976)
		(end 32.794702 -289.112452)
		(width 0.20066)
		(layer "F.Cu")
		(net "M_C_CPU1_SA_DQ<23>")
	)
	(segment
		(start 32.51708 -289.541712)
		(end 32.666178 -289.392614)
		(width 0.20066)
		(layer "F.Cu")
		(net "M_C_CPU1_SA_DQ<23>")
	)
	(segment
		(start 93.423994 -266.128246)
		(end 93.423994 -265.592306)
		(width 0.20066)
		(layer "F.Cu")
		(net "M_C_CPU1_SA_DQ<23>")
	)
	(segment
		(start 31.972758 -289.541712)
		(end 32.51708 -289.541712)
		(width 0.20066)
		(layer "F.Cu")
		(net "M_C_CPU1_SA_DQ<23>")
	)
	(segment
		(start 32.794702 -289.112452)
		(end 33.189926 -289.112452)
		(width 0.20066)
		(layer "F.Cu")
		(net "M_C_CPU1_SA_DQ<23>")
	)
	(segment
		(start 34.055812 -289.11677)
		(end 34.871914 -289.11677)
		(width 0.20066)
		(layer "F.Cu")
		(net "M_C_CPU1_SA_DQ<23>")
	)
	(segment
		(start 29.899864 -289.541712)
		(end 31.972758 -289.541712)
		(width 0.1016)
		(layer "F.Cu")
		(net "M_C_CPU1_SA_DQ<23>")
	)
	(segment
		(start 33.848294 -289.324288)
		(end 34.055812 -289.11677)
		(width 0.20066)
		(layer "F.Cu")
		(net "M_C_CPU1_SA_DQ<23>")
	)
	(segment
		(start 29.151326 -289.242754)
		(end 29.151326 -289.413442)
		(width 0.20066)
		(layer "F.Cu")
		(net "M_C_CPU1_SA_DQ<23>")
	)
	(segment
		(start 29.025342 -289.11677)
		(end 29.151326 -289.242754)
		(width 0.20066)
		(layer "F.Cu")
		(net "M_C_CPU1_SA_DQ<23>")
	)
	(segment
		(start 29.647642 -289.555936)
		(end 29.661866 -289.541712)
		(width 0.101854)
		(layer "F.Cu")
		(net "M_C_CPU1_SA_DQ<23>")
	)
	(segment
		(start 33.401762 -289.324288)
		(end 33.848294 -289.324288)
		(width 0.20066)
		(layer "F.Cu")
		(net "M_C_CPU1_SA_DQ<23>")
	)
	(segment
		(start 33.189926 -289.112452)
		(end 33.401762 -289.324288)
		(width 0.20066)
		(layer "F.Cu")
		(net "M_C_CPU1_SA_DQ<23>")
	)
	(segment
		(start 42.63644 -287.592516)
		(end 42.63644 -287.11779)
		(width 0.18288)
		(layer "In4.Cu")
		(net "M_C_CPU1_SA_DQ<23>")
	)
	(segment
		(start 44.067984 -287.775396)
		(end 42.81932 -287.775396)
		(width 0.18288)
		(layer "In4.Cu")
		(net "M_C_CPU1_SA_DQ<23>")
	)
	(segment
		(start 61.684408 -285.664656)
		(end 60.502292 -285.664656)
		(width 0.18288)
		(layer "In4.Cu")
		(net "M_C_CPU1_SA_DQ<23>")
	)
	(segment
		(start 37.699696 -287.36671)
		(end 37.699696 -288.253678)
		(width 0.18288)
		(layer "In4.Cu")
		(net "M_C_CPU1_SA_DQ<23>")
	)
	(segment
		(start 88.442546 -265.638788)
		(end 88.442292 -265.638534)
		(width 0.088646)
		(layer "In4.Cu")
		(net "M_C_CPU1_SA_DQ<23>")
	)
	(segment
		(start 40.09009 -286.977074)
		(end 40.09009 -287.592516)
		(width 0.18288)
		(layer "In4.Cu")
		(net "M_C_CPU1_SA_DQ<23>")
	)
	(segment
		(start 59.164474 -286.237934)
		(end 58.915554 -285.989014)
		(width 0.18288)
		(layer "In4.Cu")
		(net "M_C_CPU1_SA_DQ<23>")
	)
	(segment
		(start 40.96385 -287.775396)
		(end 40.78097 -287.592516)
		(width 0.18288)
		(layer "In4.Cu")
		(net "M_C_CPU1_SA_DQ<23>")
	)
	(segment
		(start 50.54981 -288.16427)
		(end 49.930304 -288.16427)
		(width 0.18288)
		(layer "In4.Cu")
		(net "M_C_CPU1_SA_DQ<23>")
	)
	(segment
		(start 37.429948 -288.523426)
		(end 36.570158 -288.523426)
		(width 0.18288)
		(layer "In4.Cu")
		(net "M_C_CPU1_SA_DQ<23>")
	)
	(segment
		(start 55.135018 -288.097214)
		(end 51.571652 -288.097214)
		(width 0.18288)
		(layer "In4.Cu")
		(net "M_C_CPU1_SA_DQ<23>")
	)
	(segment
		(start 42.81932 -287.775396)
		(end 42.63644 -287.592516)
		(width 0.18288)
		(layer "In4.Cu")
		(net "M_C_CPU1_SA_DQ<23>")
	)
	(segment
		(start 41.94556 -287.11779)
		(end 41.94556 -287.592516)
		(width 0.18288)
		(layer "In4.Cu")
		(net "M_C_CPU1_SA_DQ<23>")
	)
	(segment
		(start 64.237616 -284.38348)
		(end 63.565786 -284.38348)
		(width 0.18288)
		(layer "In4.Cu")
		(net "M_C_CPU1_SA_DQ<23>")
	)
	(segment
		(start 40.09009 -287.592516)
		(end 39.15918 -288.523426)
		(width 0.18288)
		(layer "In4.Cu")
		(net "M_C_CPU1_SA_DQ<23>")
	)
	(segment
		(start 38.390576 -288.340546)
		(end 38.390576 -287.36671)
		(width 0.18288)
		(layer "In4.Cu")
		(net "M_C_CPU1_SA_DQ<23>")
	)
	(segment
		(start 90.887296 -265.638788)
		(end 90.881454 -265.635232)
		(width 0.088646)
		(layer "In4.Cu")
		(net "M_C_CPU1_SA_DQ<23>")
	)
	(segment
		(start 40.59809 -286.794194)
		(end 40.27297 -286.794194)
		(width 0.18288)
		(layer "In4.Cu")
		(net "M_C_CPU1_SA_DQ<23>")
	)
	(segment
		(start 60.502292 -285.664656)
		(end 59.929014 -286.237934)
		(width 0.18288)
		(layer "In4.Cu")
		(net "M_C_CPU1_SA_DQ<23>")
	)
	(segment
		(start 90.893138 -265.64209)
		(end 90.887296 -265.638788)
		(width 0.088646)
		(layer "In4.Cu")
		(net "M_C_CPU1_SA_DQ<23>")
	)
	(segment
		(start 38.573456 -288.523426)
		(end 38.390576 -288.340546)
		(width 0.18288)
		(layer "In4.Cu")
		(net "M_C_CPU1_SA_DQ<23>")
	)
	(segment
		(start 55.948072 -287.28416)
		(end 55.135018 -288.097214)
		(width 0.18288)
		(layer "In4.Cu")
		(net "M_C_CPU1_SA_DQ<23>")
	)
	(segment
		(start 91.827096 -265.638788)
		(end 91.821254 -265.635232)
		(width 0.088646)
		(layer "In4.Cu")
		(net "M_C_CPU1_SA_DQ<23>")
	)
	(segment
		(start 80.77073 -266.51458)
		(end 68.946776 -278.338534)
		(width 0.18288)
		(layer "In4.Cu")
		(net "M_C_CPU1_SA_DQ<23>")
	)
	(segment
		(start 45.883576 -287.988248)
		(end 44.280836 -287.988248)
		(width 0.18288)
		(layer "In4.Cu")
		(net "M_C_CPU1_SA_DQ<23>")
	)
	(segment
		(start 58.30062 -285.989014)
		(end 57.005474 -287.28416)
		(width 0.18288)
		(layer "In4.Cu")
		(net "M_C_CPU1_SA_DQ<23>")
	)
	(segment
		(start 58.915554 -285.989014)
		(end 58.30062 -285.989014)
		(width 0.18288)
		(layer "In4.Cu")
		(net "M_C_CPU1_SA_DQ<23>")
	)
	(segment
		(start 67.481958 -281.87523)
		(end 66.321432 -283.035756)
		(width 0.18288)
		(layer "In4.Cu")
		(net "M_C_CPU1_SA_DQ<23>")
	)
	(segment
		(start 36.570158 -288.523426)
		(end 35.976814 -289.11677)
		(width 0.18288)
		(layer "In4.Cu")
		(net "M_C_CPU1_SA_DQ<23>")
	)
	(segment
		(start 51.179222 -287.84169)
		(end 50.98161 -287.84169)
		(width 0.18288)
		(layer "In4.Cu")
		(net "M_C_CPU1_SA_DQ<23>")
	)
	(segment
		(start 91.832938 -265.64209)
		(end 91.827096 -265.638788)
		(width 0.088646)
		(layer "In4.Cu")
		(net "M_C_CPU1_SA_DQ<23>")
	)
	(segment
		(start 50.98161 -287.84169)
		(end 50.821844 -287.907984)
		(width 0.18288)
		(layer "In4.Cu")
		(net "M_C_CPU1_SA_DQ<23>")
	)
	(segment
		(start 51.571652 -288.097214)
		(end 51.412902 -287.938464)
		(width 0.18288)
		(layer "In4.Cu")
		(net "M_C_CPU1_SA_DQ<23>")
	)
	(segment
		(start 65.58534 -283.035756)
		(end 64.237616 -284.38348)
		(width 0.18288)
		(layer "In4.Cu")
		(net "M_C_CPU1_SA_DQ<23>")
	)
	(segment
		(start 89.951814 -265.641328)
		(end 89.947496 -265.638788)
		(width 0.088646)
		(layer "In4.Cu")
		(net "M_C_CPU1_SA_DQ<23>")
	)
	(segment
		(start 63.565786 -284.38348)
		(end 62.667896 -285.28137)
		(width 0.18288)
		(layer "In4.Cu")
		(net "M_C_CPU1_SA_DQ<23>")
	)
	(segment
		(start 38.207696 -287.18383)
		(end 37.882576 -287.18383)
		(width 0.18288)
		(layer "In4.Cu")
		(net "M_C_CPU1_SA_DQ<23>")
	)
	(segment
		(start 89.011506 -265.64082)
		(end 89.007696 -265.638788)
		(width 0.088646)
		(layer "In4.Cu")
		(net "M_C_CPU1_SA_DQ<23>")
	)
	(segment
		(start 40.78097 -286.977074)
		(end 40.59809 -286.794194)
		(width 0.18288)
		(layer "In4.Cu")
		(net "M_C_CPU1_SA_DQ<23>")
	)
	(segment
		(start 50.795174 -287.918906)
		(end 50.54981 -288.16427)
		(width 0.18288)
		(layer "In4.Cu")
		(net "M_C_CPU1_SA_DQ<23>")
	)
	(segment
		(start 40.27297 -286.794194)
		(end 40.09009 -286.977074)
		(width 0.18288)
		(layer "In4.Cu")
		(net "M_C_CPU1_SA_DQ<23>")
	)
	(segment
		(start 59.929014 -286.237934)
		(end 59.164474 -286.237934)
		(width 0.18288)
		(layer "In4.Cu")
		(net "M_C_CPU1_SA_DQ<23>")
	)
	(segment
		(start 92.920058 -265.919458)
		(end 92.705936 -265.705336)
		(width 0.088646)
		(layer "In4.Cu")
		(net "M_C_CPU1_SA_DQ<23>")
	)
	(segment
		(start 44.280836 -287.988248)
		(end 44.067984 -287.775396)
		(width 0.18288)
		(layer "In4.Cu")
		(net "M_C_CPU1_SA_DQ<23>")
	)
	(segment
		(start 89.007696 -265.638788)
		(end 89.001854 -265.635232)
		(width 0.088646)
		(layer "In4.Cu")
		(net "M_C_CPU1_SA_DQ<23>")
	)
	(segment
		(start 68.946776 -278.338534)
		(end 67.481958 -281.87523)
		(width 0.18288)
		(layer "In4.Cu")
		(net "M_C_CPU1_SA_DQ<23>")
	)
	(segment
		(start 39.15918 -288.523426)
		(end 38.573456 -288.523426)
		(width 0.18288)
		(layer "In4.Cu")
		(net "M_C_CPU1_SA_DQ<23>")
	)
	(segment
		(start 37.882576 -287.18383)
		(end 37.699696 -287.36671)
		(width 0.18288)
		(layer "In4.Cu")
		(net "M_C_CPU1_SA_DQ<23>")
	)
	(segment
		(start 37.699696 -288.253678)
		(end 37.429948 -288.523426)
		(width 0.18288)
		(layer "In4.Cu")
		(net "M_C_CPU1_SA_DQ<23>")
	)
	(segment
		(start 49.402746 -288.691828)
		(end 46.587156 -288.691828)
		(width 0.18288)
		(layer "In4.Cu")
		(net "M_C_CPU1_SA_DQ<23>")
	)
	(segment
		(start 83.379056 -265.975592)
		(end 83.379056 -266.211812)
		(width 0.088646)
		(layer "In4.Cu")
		(net "M_C_CPU1_SA_DQ<23>")
	)
	(segment
		(start 62.067694 -285.28137)
		(end 61.684408 -285.664656)
		(width 0.18288)
		(layer "In4.Cu")
		(net "M_C_CPU1_SA_DQ<23>")
	)
	(segment
		(start 42.12844 -286.93491)
		(end 41.94556 -287.11779)
		(width 0.18288)
		(layer "In4.Cu")
		(net "M_C_CPU1_SA_DQ<23>")
	)
	(segment
		(start 42.63644 -287.11779)
		(end 42.45356 -286.93491)
		(width 0.18288)
		(layer "In4.Cu")
		(net "M_C_CPU1_SA_DQ<23>")
	)
	(segment
		(start 62.667896 -285.28137)
		(end 62.067694 -285.28137)
		(width 0.18288)
		(layer "In4.Cu")
		(net "M_C_CPU1_SA_DQ<23>")
	)
	(segment
		(start 82.784188 -266.51458)
		(end 80.77073 -266.51458)
		(width 0.18288)
		(layer "In4.Cu")
		(net "M_C_CPU1_SA_DQ<23>")
	)
	(segment
		(start 46.587156 -288.691828)
		(end 45.883576 -287.988248)
		(width 0.18288)
		(layer "In4.Cu")
		(net "M_C_CPU1_SA_DQ<23>")
	)
	(segment
		(start 66.321432 -283.035756)
		(end 65.58534 -283.035756)
		(width 0.18288)
		(layer "In4.Cu")
		(net "M_C_CPU1_SA_DQ<23>")
	)
	(segment
		(start 38.390576 -287.36671)
		(end 38.207696 -287.18383)
		(width 0.18288)
		(layer "In4.Cu")
		(net "M_C_CPU1_SA_DQ<23>")
	)
	(segment
		(start 42.45356 -286.93491)
		(end 42.12844 -286.93491)
		(width 0.18288)
		(layer "In4.Cu")
		(net "M_C_CPU1_SA_DQ<23>")
	)
	(segment
		(start 83.076288 -266.51458)
		(end 82.784188 -266.51458)
		(width 0.088646)
		(layer "In4.Cu")
		(net "M_C_CPU1_SA_DQ<23>")
	)
	(segment
		(start 83.626198 -265.72845)
		(end 83.379056 -265.975592)
		(width 0.088646)
		(layer "In4.Cu")
		(net "M_C_CPU1_SA_DQ<23>")
	)
	(segment
		(start 83.379056 -266.211812)
		(end 83.076288 -266.51458)
		(width 0.088646)
		(layer "In4.Cu")
		(net "M_C_CPU1_SA_DQ<23>")
	)
	(segment
		(start 49.930304 -288.16427)
		(end 49.402746 -288.691828)
		(width 0.18288)
		(layer "In4.Cu")
		(net "M_C_CPU1_SA_DQ<23>")
	)
	(segment
		(start 41.94556 -287.592516)
		(end 41.76268 -287.775396)
		(width 0.18288)
		(layer "In4.Cu")
		(net "M_C_CPU1_SA_DQ<23>")
	)
	(segment
		(start 41.76268 -287.775396)
		(end 40.96385 -287.775396)
		(width 0.18288)
		(layer "In4.Cu")
		(net "M_C_CPU1_SA_DQ<23>")
	)
	(segment
		(start 40.78097 -287.592516)
		(end 40.78097 -286.977074)
		(width 0.18288)
		(layer "In4.Cu")
		(net "M_C_CPU1_SA_DQ<23>")
	)
	(segment
		(start 51.412902 -287.938464)
		(end 51.179222 -287.84169)
		(width 0.18288)
		(layer "In4.Cu")
		(net "M_C_CPU1_SA_DQ<23>")
	)
	(segment
		(start 50.821844 -287.907984)
		(end 50.795174 -287.918906)
		(width 0.18288)
		(layer "In4.Cu")
		(net "M_C_CPU1_SA_DQ<23>")
	)
	(segment
		(start 57.005474 -287.28416)
		(end 55.948072 -287.28416)
		(width 0.18288)
		(layer "In4.Cu")
		(net "M_C_CPU1_SA_DQ<23>")
	)
	(arc
		(start 90.881454 -265.635232)
		(mid 90.601319 -265.562916)
		(end 90.322146 -265.638788)
		(width 0.088646)
		(layer "In4.Cu")
		(net "M_C_CPU1_SA_DQ<23>")
	)
	(arc
		(start 91.821254 -265.635232)
		(mid 91.541119 -265.562916)
		(end 91.261946 -265.638788)
		(width 0.088646)
		(layer "In4.Cu")
		(net "M_C_CPU1_SA_DQ<23>")
	)
	(arc
		(start 85.248496 -265.638534)
		(mid 84.965794 -265.562792)
		(end 84.683092 -265.638534)
		(width 0.088646)
		(layer "In4.Cu")
		(net "M_C_CPU1_SA_DQ<23>")
	)
	(arc
		(start 89.001854 -265.635232)
		(mid 88.721719 -265.562916)
		(end 88.442546 -265.638788)
		(width 0.088646)
		(layer "In4.Cu")
		(net "M_C_CPU1_SA_DQ<23>")
	)
	(arc
		(start 87.502492 -265.638534)
		(mid 87.315294 -265.688677)
		(end 87.128096 -265.638534)
		(width 0.088646)
		(layer "In4.Cu")
		(net "M_C_CPU1_SA_DQ<23>")
	)
	(arc
		(start 89.382346 -265.638788)
		(mid 89.197196 -265.688892)
		(end 89.011506 -265.64082)
		(width 0.088646)
		(layer "In4.Cu")
		(net "M_C_CPU1_SA_DQ<23>")
	)
	(arc
		(start 89.947496 -265.638788)
		(mid 89.664938 -265.563139)
		(end 89.382346 -265.638788)
		(width 0.088646)
		(layer "In4.Cu")
		(net "M_C_CPU1_SA_DQ<23>")
	)
	(arc
		(start 92.201746 -265.638788)
		(mid 92.017792 -265.688883)
		(end 91.832938 -265.64209)
		(width 0.088646)
		(layer "In4.Cu")
		(net "M_C_CPU1_SA_DQ<23>")
	)
	(arc
		(start 84.308696 -265.638534)
		(mid 83.952173 -265.567631)
		(end 83.626198 -265.72845)
		(width 0.088646)
		(layer "In4.Cu")
		(net "M_C_CPU1_SA_DQ<23>")
	)
	(arc
		(start 88.442292 -265.638534)
		(mid 88.255094 -265.688677)
		(end 88.067896 -265.638534)
		(width 0.088646)
		(layer "In4.Cu")
		(net "M_C_CPU1_SA_DQ<23>")
	)
	(arc
		(start 85.622892 -265.638534)
		(mid 85.435694 -265.688677)
		(end 85.248496 -265.638534)
		(width 0.088646)
		(layer "In4.Cu")
		(net "M_C_CPU1_SA_DQ<23>")
	)
	(arc
		(start 90.322146 -265.638788)
		(mid 90.137309 -265.689015)
		(end 89.951814 -265.641328)
		(width 0.088646)
		(layer "In4.Cu")
		(net "M_C_CPU1_SA_DQ<23>")
	)
	(arc
		(start 88.067896 -265.638534)
		(mid 87.785194 -265.562792)
		(end 87.502492 -265.638534)
		(width 0.088646)
		(layer "In4.Cu")
		(net "M_C_CPU1_SA_DQ<23>")
	)
	(arc
		(start 91.261946 -265.638788)
		(mid 91.077992 -265.688883)
		(end 90.893138 -265.64209)
		(width 0.088646)
		(layer "In4.Cu")
		(net "M_C_CPU1_SA_DQ<23>")
	)
	(arc
		(start 86.188296 -265.638534)
		(mid 85.905594 -265.562792)
		(end 85.622892 -265.638534)
		(width 0.088646)
		(layer "In4.Cu")
		(net "M_C_CPU1_SA_DQ<23>")
	)
	(arc
		(start 84.683092 -265.638534)
		(mid 84.495894 -265.688677)
		(end 84.308696 -265.638534)
		(width 0.088646)
		(layer "In4.Cu")
		(net "M_C_CPU1_SA_DQ<23>")
	)
	(arc
		(start 86.562692 -265.638534)
		(mid 86.375494 -265.688677)
		(end 86.188296 -265.638534)
		(width 0.088646)
		(layer "In4.Cu")
		(net "M_C_CPU1_SA_DQ<23>")
	)
	(arc
		(start 87.128096 -265.638534)
		(mid 86.845394 -265.562792)
		(end 86.562692 -265.638534)
		(width 0.088646)
		(layer "In4.Cu")
		(net "M_C_CPU1_SA_DQ<23>")
	)
	(arc
		(start 93.423994 -266.128246)
		(mid 93.151246 -266.073993)
		(end 92.920058 -265.919458)
		(width 0.088646)
		(layer "In4.Cu")
		(net "M_C_CPU1_SA_DQ<23>")
	)
	(arc
		(start 92.705936 -265.705336)
		(mid 92.465142 -265.586561)
		(end 92.201746 -265.638788)
		(width 0.088646)
		(layer "In4.Cu")
		(net "M_C_CPU1_SA_DQ<23>")
	)
	(segment
		(start 29.647642 -290.38169)
		(end 29.657802 -290.39185)
		(width 0.101854)
		(layer "F.Cu")
		(net "M_C_CPU1_SA_DQ<22>")
	)
	(segment
		(start 35.976814 -290.816792)
		(end 34.871914 -290.816792)
		(width 0.20066)
		(layer "F.Cu")
		(net "M_C_CPU1_SA_DQ<22>")
	)
	(segment
		(start 29.912818 -290.39185)
		(end 31.972758 -290.39185)
		(width 0.1016)
		(layer "F.Cu")
		(net "M_C_CPU1_SA_DQ<22>")
	)
	(segment
		(start 32.605726 -290.39185)
		(end 32.74949 -290.535614)
		(width 0.20066)
		(layer "F.Cu")
		(net "M_C_CPU1_SA_DQ<22>")
	)
	(segment
		(start 29.657802 -290.39185)
		(end 29.912818 -290.39185)
		(width 0.101854)
		(layer "F.Cu")
		(net "M_C_CPU1_SA_DQ<22>")
	)
	(segment
		(start 32.74949 -290.861242)
		(end 32.916876 -291.028628)
		(width 0.20066)
		(layer "F.Cu")
		(net "M_C_CPU1_SA_DQ<22>")
	)
	(segment
		(start 28.91028 -290.38169)
		(end 29.647642 -290.38169)
		(width 0.20066)
		(layer "F.Cu")
		(net "M_C_CPU1_SA_DQ<22>")
	)
	(segment
		(start 27.328114 -290.816792)
		(end 28.475178 -290.816792)
		(width 0.20066)
		(layer "F.Cu")
		(net "M_C_CPU1_SA_DQ<22>")
	)
	(segment
		(start 93.894148 -266.406122)
		(end 93.894148 -266.941808)
		(width 0.20066)
		(layer "F.Cu")
		(net "M_C_CPU1_SA_DQ<22>")
	)
	(segment
		(start 32.916876 -291.028628)
		(end 33.345374 -291.028628)
		(width 0.20066)
		(layer "F.Cu")
		(net "M_C_CPU1_SA_DQ<22>")
	)
	(segment
		(start 33.55721 -290.816792)
		(end 34.871914 -290.816792)
		(width 0.20066)
		(layer "F.Cu")
		(net "M_C_CPU1_SA_DQ<22>")
	)
	(segment
		(start 93.893894 -266.405868)
		(end 93.894148 -266.406122)
		(width 0.20066)
		(layer "F.Cu")
		(net "M_C_CPU1_SA_DQ<22>")
	)
	(segment
		(start 31.972758 -290.39185)
		(end 32.605726 -290.39185)
		(width 0.20066)
		(layer "F.Cu")
		(net "M_C_CPU1_SA_DQ<22>")
	)
	(segment
		(start 33.345374 -291.028628)
		(end 33.55721 -290.816792)
		(width 0.20066)
		(layer "F.Cu")
		(net "M_C_CPU1_SA_DQ<22>")
	)
	(segment
		(start 28.475178 -290.816792)
		(end 28.91028 -290.38169)
		(width 0.20066)
		(layer "F.Cu")
		(net "M_C_CPU1_SA_DQ<22>")
	)
	(segment
		(start 32.74949 -290.535614)
		(end 32.74949 -290.861242)
		(width 0.20066)
		(layer "F.Cu")
		(net "M_C_CPU1_SA_DQ<22>")
	)
	(segment
		(start 89.477596 -266.45235)
		(end 89.477596 -266.452604)
		(width 0.088646)
		(layer "In4.Cu")
		(net "M_C_CPU1_SA_DQ<22>")
	)
	(segment
		(start 46.502574 -290.39185)
		(end 45.61332 -289.502596)
		(width 0.18288)
		(layer "In4.Cu")
		(net "M_C_CPU1_SA_DQ<22>")
	)
	(segment
		(start 40.835834 -289.530282)
		(end 40.835834 -290.171378)
		(width 0.18288)
		(layer "In4.Cu")
		(net "M_C_CPU1_SA_DQ<22>")
	)
	(segment
		(start 65.95618 -284.27807)
		(end 64.173608 -286.060642)
		(width 0.18288)
		(layer "In4.Cu")
		(net "M_C_CPU1_SA_DQ<22>")
	)
	(segment
		(start 56.489346 -290.509706)
		(end 55.86349 -290.509706)
		(width 0.18288)
		(layer "In4.Cu")
		(net "M_C_CPU1_SA_DQ<22>")
	)
	(segment
		(start 37.85235 -290.331906)
		(end 37.66947 -290.149026)
		(width 0.18288)
		(layer "In4.Cu")
		(net "M_C_CPU1_SA_DQ<22>")
	)
	(segment
		(start 92.677488 -266.449048)
		(end 92.671646 -266.452604)
		(width 0.088646)
		(layer "In4.Cu")
		(net "M_C_CPU1_SA_DQ<22>")
	)
	(segment
		(start 37.66947 -290.149026)
		(end 36.64458 -290.149026)
		(width 0.18288)
		(layer "In4.Cu")
		(net "M_C_CPU1_SA_DQ<22>")
	)
	(segment
		(start 43.921934 -289.336734)
		(end 43.9166 -289.342068)
		(width 0.18288)
		(layer "In4.Cu")
		(net "M_C_CPU1_SA_DQ<22>")
	)
	(segment
		(start 41.024048 -289.342068)
		(end 40.835834 -289.530282)
		(width 0.18288)
		(layer "In4.Cu")
		(net "M_C_CPU1_SA_DQ<22>")
	)
	(segment
		(start 59.05881 -287.634172)
		(end 58.395108 -287.634172)
		(width 0.18288)
		(layer "In4.Cu")
		(net "M_C_CPU1_SA_DQ<22>")
	)
	(segment
		(start 37.85235 -290.552378)
		(end 37.85235 -290.331906)
		(width 0.18288)
		(layer "In4.Cu")
		(net "M_C_CPU1_SA_DQ<22>")
	)
	(segment
		(start 38.72611 -290.149026)
		(end 38.54323 -290.331906)
		(width 0.18288)
		(layer "In4.Cu")
		(net "M_C_CPU1_SA_DQ<22>")
	)
	(segment
		(start 41.992042 -289.524948)
		(end 41.809162 -289.342068)
		(width 0.18288)
		(layer "In4.Cu")
		(net "M_C_CPU1_SA_DQ<22>")
	)
	(segment
		(start 59.280298 -287.85566)
		(end 59.05881 -287.634172)
		(width 0.18288)
		(layer "In4.Cu")
		(net "M_C_CPU1_SA_DQ<22>")
	)
	(segment
		(start 50.315114 -289.541712)
		(end 49.464976 -290.39185)
		(width 0.18288)
		(layer "In4.Cu")
		(net "M_C_CPU1_SA_DQ<22>")
	)
	(segment
		(start 41.809162 -289.342068)
		(end 41.024048 -289.342068)
		(width 0.18288)
		(layer "In4.Cu")
		(net "M_C_CPU1_SA_DQ<22>")
	)
	(segment
		(start 53.60035 -289.863022)
		(end 53.132482 -289.863022)
		(width 0.18288)
		(layer "In4.Cu")
		(net "M_C_CPU1_SA_DQ<22>")
	)
	(segment
		(start 40.526462 -290.48075)
		(end 40.02659 -290.48075)
		(width 0.18288)
		(layer "In4.Cu")
		(net "M_C_CPU1_SA_DQ<22>")
	)
	(segment
		(start 53.132482 -289.863022)
		(end 52.811172 -289.541712)
		(width 0.18288)
		(layer "In4.Cu")
		(net "M_C_CPU1_SA_DQ<22>")
	)
	(segment
		(start 49.464976 -290.39185)
		(end 46.502574 -290.39185)
		(width 0.18288)
		(layer "In4.Cu")
		(net "M_C_CPU1_SA_DQ<22>")
	)
	(segment
		(start 53.92166 -289.541712)
		(end 53.60035 -289.863022)
		(width 0.18288)
		(layer "In4.Cu")
		(net "M_C_CPU1_SA_DQ<22>")
	)
	(segment
		(start 42.174922 -290.318444)
		(end 41.992042 -290.135564)
		(width 0.18288)
		(layer "In4.Cu")
		(net "M_C_CPU1_SA_DQ<22>")
	)
	(segment
		(start 43.9166 -289.342068)
		(end 42.865802 -289.342068)
		(width 0.18288)
		(layer "In4.Cu")
		(net "M_C_CPU1_SA_DQ<22>")
	)
	(segment
		(start 63.468758 -286.060642)
		(end 62.62497 -286.90443)
		(width 0.18288)
		(layer "In4.Cu")
		(net "M_C_CPU1_SA_DQ<22>")
	)
	(segment
		(start 92.671646 -266.452604)
		(end 92.665804 -266.455906)
		(width 0.088646)
		(layer "In4.Cu")
		(net "M_C_CPU1_SA_DQ<22>")
	)
	(segment
		(start 41.992042 -290.135564)
		(end 41.992042 -289.524948)
		(width 0.18288)
		(layer "In4.Cu")
		(net "M_C_CPU1_SA_DQ<22>")
	)
	(segment
		(start 84.096098 -266.542012)
		(end 83.12785 -267.51026)
		(width 0.088646)
		(layer "In4.Cu")
		(net "M_C_CPU1_SA_DQ<22>")
	)
	(segment
		(start 40.02659 -290.48075)
		(end 39.694866 -290.149026)
		(width 0.18288)
		(layer "In4.Cu")
		(net "M_C_CPU1_SA_DQ<22>")
	)
	(segment
		(start 38.54323 -290.331906)
		(end 38.54323 -290.552378)
		(width 0.18288)
		(layer "In4.Cu")
		(net "M_C_CPU1_SA_DQ<22>")
	)
	(segment
		(start 42.682922 -290.135564)
		(end 42.500042 -290.318444)
		(width 0.18288)
		(layer "In4.Cu")
		(net "M_C_CPU1_SA_DQ<22>")
	)
	(segment
		(start 81.25079 -267.51026)
		(end 69.981826 -278.779224)
		(width 0.18288)
		(layer "In4.Cu")
		(net "M_C_CPU1_SA_DQ<22>")
	)
	(segment
		(start 39.694866 -290.149026)
		(end 38.72611 -290.149026)
		(width 0.18288)
		(layer "In4.Cu")
		(net "M_C_CPU1_SA_DQ<22>")
	)
	(segment
		(start 62.62497 -286.90443)
		(end 60.806076 -286.90443)
		(width 0.18288)
		(layer "In4.Cu")
		(net "M_C_CPU1_SA_DQ<22>")
	)
	(segment
		(start 59.854846 -287.85566)
		(end 59.280298 -287.85566)
		(width 0.18288)
		(layer "In4.Cu")
		(net "M_C_CPU1_SA_DQ<22>")
	)
	(segment
		(start 38.03523 -290.735258)
		(end 37.85235 -290.552378)
		(width 0.18288)
		(layer "In4.Cu")
		(net "M_C_CPU1_SA_DQ<22>")
	)
	(segment
		(start 44.241974 -289.656774)
		(end 43.921934 -289.336734)
		(width 0.18288)
		(layer "In4.Cu")
		(net "M_C_CPU1_SA_DQ<22>")
	)
	(segment
		(start 58.395108 -287.634172)
		(end 57.930542 -288.098738)
		(width 0.18288)
		(layer "In4.Cu")
		(net "M_C_CPU1_SA_DQ<22>")
	)
	(segment
		(start 42.682922 -289.524948)
		(end 42.682922 -290.135564)
		(width 0.18288)
		(layer "In4.Cu")
		(net "M_C_CPU1_SA_DQ<22>")
	)
	(segment
		(start 38.54323 -290.552378)
		(end 38.36035 -290.735258)
		(width 0.18288)
		(layer "In4.Cu")
		(net "M_C_CPU1_SA_DQ<22>")
	)
	(segment
		(start 36.64458 -290.149026)
		(end 35.976814 -290.816792)
		(width 0.18288)
		(layer "In4.Cu")
		(net "M_C_CPU1_SA_DQ<22>")
	)
	(segment
		(start 88.916256 -266.450318)
		(end 88.912192 -266.45235)
		(width 0.088646)
		(layer "In4.Cu")
		(net "M_C_CPU1_SA_DQ<22>")
	)
	(segment
		(start 57.930542 -288.098738)
		(end 57.930542 -289.06851)
		(width 0.18288)
		(layer "In4.Cu")
		(net "M_C_CPU1_SA_DQ<22>")
	)
	(segment
		(start 68.396104 -282.607258)
		(end 66.725292 -284.27807)
		(width 0.18288)
		(layer "In4.Cu")
		(net "M_C_CPU1_SA_DQ<22>")
	)
	(segment
		(start 69.981826 -278.779224)
		(end 68.396104 -282.607258)
		(width 0.18288)
		(layer "In4.Cu")
		(net "M_C_CPU1_SA_DQ<22>")
	)
	(segment
		(start 40.835834 -290.171378)
		(end 40.526462 -290.48075)
		(width 0.18288)
		(layer "In4.Cu")
		(net "M_C_CPU1_SA_DQ<22>")
	)
	(segment
		(start 42.865802 -289.342068)
		(end 42.682922 -289.524948)
		(width 0.18288)
		(layer "In4.Cu")
		(net "M_C_CPU1_SA_DQ<22>")
	)
	(segment
		(start 45.026326 -289.656774)
		(end 44.241974 -289.656774)
		(width 0.18288)
		(layer "In4.Cu")
		(net "M_C_CPU1_SA_DQ<22>")
	)
	(segment
		(start 54.895496 -289.541712)
		(end 53.92166 -289.541712)
		(width 0.18288)
		(layer "In4.Cu")
		(net "M_C_CPU1_SA_DQ<22>")
	)
	(segment
		(start 83.12785 -267.51026)
		(end 82.784188 -267.51026)
		(width 0.088646)
		(layer "In4.Cu")
		(net "M_C_CPU1_SA_DQ<22>")
	)
	(segment
		(start 93.310964 -266.495276)
		(end 93.236796 -266.452604)
		(width 0.088646)
		(layer "In4.Cu")
		(net "M_C_CPU1_SA_DQ<22>")
	)
	(segment
		(start 42.500042 -290.318444)
		(end 42.174922 -290.318444)
		(width 0.18288)
		(layer "In4.Cu")
		(net "M_C_CPU1_SA_DQ<22>")
	)
	(segment
		(start 91.737688 -266.449048)
		(end 91.731846 -266.452604)
		(width 0.088646)
		(layer "In4.Cu")
		(net "M_C_CPU1_SA_DQ<22>")
	)
	(segment
		(start 55.86349 -290.509706)
		(end 54.895496 -289.541712)
		(width 0.18288)
		(layer "In4.Cu")
		(net "M_C_CPU1_SA_DQ<22>")
	)
	(segment
		(start 45.61332 -289.502596)
		(end 45.180504 -289.502596)
		(width 0.18288)
		(layer "In4.Cu")
		(net "M_C_CPU1_SA_DQ<22>")
	)
	(segment
		(start 52.811172 -289.541712)
		(end 50.315114 -289.541712)
		(width 0.18288)
		(layer "In4.Cu")
		(net "M_C_CPU1_SA_DQ<22>")
	)
	(segment
		(start 91.731846 -266.452604)
		(end 91.726004 -266.455906)
		(width 0.088646)
		(layer "In4.Cu")
		(net "M_C_CPU1_SA_DQ<22>")
	)
	(segment
		(start 45.180504 -289.502596)
		(end 45.026326 -289.656774)
		(width 0.18288)
		(layer "In4.Cu")
		(net "M_C_CPU1_SA_DQ<22>")
	)
	(segment
		(start 64.173608 -286.060642)
		(end 63.468758 -286.060642)
		(width 0.18288)
		(layer "In4.Cu")
		(net "M_C_CPU1_SA_DQ<22>")
	)
	(segment
		(start 57.930542 -289.06851)
		(end 56.489346 -290.509706)
		(width 0.18288)
		(layer "In4.Cu")
		(net "M_C_CPU1_SA_DQ<22>")
	)
	(segment
		(start 66.725292 -284.27807)
		(end 65.95618 -284.27807)
		(width 0.18288)
		(layer "In4.Cu")
		(net "M_C_CPU1_SA_DQ<22>")
	)
	(segment
		(start 38.36035 -290.735258)
		(end 38.03523 -290.735258)
		(width 0.18288)
		(layer "In4.Cu")
		(net "M_C_CPU1_SA_DQ<22>")
	)
	(segment
		(start 60.806076 -286.90443)
		(end 59.854846 -287.85566)
		(width 0.18288)
		(layer "In4.Cu")
		(net "M_C_CPU1_SA_DQ<22>")
	)
	(segment
		(start 82.784188 -267.51026)
		(end 81.25079 -267.51026)
		(width 0.18288)
		(layer "In4.Cu")
		(net "M_C_CPU1_SA_DQ<22>")
	)
	(segment
		(start 90.797888 -266.449048)
		(end 90.791792 -266.45235)
		(width 0.088646)
		(layer "In4.Cu")
		(net "M_C_CPU1_SA_DQ<22>")
	)
	(arc
		(start 87.597996 -266.45235)
		(mid 87.315294 -266.376574)
		(end 87.032592 -266.45235)
		(width 0.088646)
		(layer "In4.Cu")
		(net "M_C_CPU1_SA_DQ<22>")
	)
	(arc
		(start 90.417396 -266.45235)
		(mid 90.134694 -266.376574)
		(end 89.851992 -266.45235)
		(width 0.088646)
		(layer "In4.Cu")
		(net "M_C_CPU1_SA_DQ<22>")
	)
	(arc
		(start 87.972392 -266.45235)
		(mid 87.785194 -266.502527)
		(end 87.597996 -266.45235)
		(width 0.088646)
		(layer "In4.Cu")
		(net "M_C_CPU1_SA_DQ<22>")
	)
	(arc
		(start 88.912192 -266.45235)
		(mid 88.724994 -266.502527)
		(end 88.537796 -266.45235)
		(width 0.088646)
		(layer "In4.Cu")
		(net "M_C_CPU1_SA_DQ<22>")
	)
	(arc
		(start 88.537796 -266.45235)
		(mid 88.255094 -266.376574)
		(end 87.972392 -266.45235)
		(width 0.088646)
		(layer "In4.Cu")
		(net "M_C_CPU1_SA_DQ<22>")
	)
	(arc
		(start 92.296996 -266.452604)
		(mid 92.017822 -266.376805)
		(end 91.737688 -266.449048)
		(width 0.088646)
		(layer "In4.Cu")
		(net "M_C_CPU1_SA_DQ<22>")
	)
	(arc
		(start 86.658196 -266.45235)
		(mid 86.375494 -266.376574)
		(end 86.092792 -266.45235)
		(width 0.088646)
		(layer "In4.Cu")
		(net "M_C_CPU1_SA_DQ<22>")
	)
	(arc
		(start 93.894148 -266.941808)
		(mid 93.617288 -266.699303)
		(end 93.310964 -266.495276)
		(width 0.088646)
		(layer "In4.Cu")
		(net "M_C_CPU1_SA_DQ<22>")
	)
	(arc
		(start 85.152992 -266.45235)
		(mid 84.965794 -266.502527)
		(end 84.778596 -266.45235)
		(width 0.088646)
		(layer "In4.Cu")
		(net "M_C_CPU1_SA_DQ<22>")
	)
	(arc
		(start 84.213192 -266.45235)
		(mid 84.151714 -266.493352)
		(end 84.096098 -266.542012)
		(width 0.088646)
		(layer "In4.Cu")
		(net "M_C_CPU1_SA_DQ<22>")
	)
	(arc
		(start 87.032592 -266.45235)
		(mid 86.845394 -266.502527)
		(end 86.658196 -266.45235)
		(width 0.088646)
		(layer "In4.Cu")
		(net "M_C_CPU1_SA_DQ<22>")
	)
	(arc
		(start 84.778596 -266.45235)
		(mid 84.495894 -266.376574)
		(end 84.213192 -266.45235)
		(width 0.088646)
		(layer "In4.Cu")
		(net "M_C_CPU1_SA_DQ<22>")
	)
	(arc
		(start 91.726004 -266.455906)
		(mid 91.541149 -266.502856)
		(end 91.357196 -266.452604)
		(width 0.088646)
		(layer "In4.Cu")
		(net "M_C_CPU1_SA_DQ<22>")
	)
	(arc
		(start 89.477596 -266.452604)
		(mid 89.197225 -266.376799)
		(end 88.916256 -266.450318)
		(width 0.088646)
		(layer "In4.Cu")
		(net "M_C_CPU1_SA_DQ<22>")
	)
	(arc
		(start 85.718396 -266.45235)
		(mid 85.435694 -266.376574)
		(end 85.152992 -266.45235)
		(width 0.088646)
		(layer "In4.Cu")
		(net "M_C_CPU1_SA_DQ<22>")
	)
	(arc
		(start 89.851992 -266.45235)
		(mid 89.664794 -266.502527)
		(end 89.477596 -266.45235)
		(width 0.088646)
		(layer "In4.Cu")
		(net "M_C_CPU1_SA_DQ<22>")
	)
	(arc
		(start 90.791792 -266.45235)
		(mid 90.604594 -266.502527)
		(end 90.417396 -266.45235)
		(width 0.088646)
		(layer "In4.Cu")
		(net "M_C_CPU1_SA_DQ<22>")
	)
	(arc
		(start 91.357196 -266.452604)
		(mid 91.078022 -266.376805)
		(end 90.797888 -266.449048)
		(width 0.088646)
		(layer "In4.Cu")
		(net "M_C_CPU1_SA_DQ<22>")
	)
	(arc
		(start 92.665804 -266.455906)
		(mid 92.480949 -266.502856)
		(end 92.296996 -266.452604)
		(width 0.088646)
		(layer "In4.Cu")
		(net "M_C_CPU1_SA_DQ<22>")
	)
	(arc
		(start 86.092792 -266.45235)
		(mid 85.905594 -266.502527)
		(end 85.718396 -266.45235)
		(width 0.088646)
		(layer "In4.Cu")
		(net "M_C_CPU1_SA_DQ<22>")
	)
	(arc
		(start 93.236796 -266.452604)
		(mid 92.957622 -266.376805)
		(end 92.677488 -266.449048)
		(width 0.088646)
		(layer "In4.Cu")
		(net "M_C_CPU1_SA_DQ<22>")
	)
	(segment
		(start 23.228046 -289.966654)
		(end 24.562308 -289.966654)
		(width 0.20066)
		(layer "F.Cu")
		(net "M_C_CPU1_SA_DQ<21>")
	)
	(segment
		(start 25.595072 -289.532822)
		(end 26.20391 -289.532822)
		(width 0.20066)
		(layer "F.Cu")
		(net "M_C_CPU1_SA_DQ<21>")
	)
	(segment
		(start 28.198318 -289.541712)
		(end 28.529026 -289.541712)
		(width 0.101854)
		(layer "F.Cu")
		(net "M_C_CPU1_SA_DQ<21>")
	)
	(segment
		(start 25.432512 -289.695382)
		(end 25.595072 -289.532822)
		(width 0.20066)
		(layer "F.Cu")
		(net "M_C_CPU1_SA_DQ<21>")
	)
	(segment
		(start 28.707588 -289.541712)
		(end 29.13253 -289.966654)
		(width 0.20066)
		(layer "F.Cu")
		(net "M_C_CPU1_SA_DQ<21>")
	)
	(segment
		(start 92.484194 -265.592306)
		(end 92.484448 -265.592306)
		(width 0.20066)
		(layer "F.Cu")
		(net "M_C_CPU1_SA_DQ<21>")
	)
	(segment
		(start 28.529026 -289.541712)
		(end 28.707588 -289.541712)
		(width 0.20066)
		(layer "F.Cu")
		(net "M_C_CPU1_SA_DQ<21>")
	)
	(segment
		(start 29.13253 -289.966654)
		(end 30.771846 -289.966654)
		(width 0.20066)
		(layer "F.Cu")
		(net "M_C_CPU1_SA_DQ<21>")
	)
	(segment
		(start 24.773636 -290.177982)
		(end 25.27808 -290.177982)
		(width 0.20066)
		(layer "F.Cu")
		(net "M_C_CPU1_SA_DQ<21>")
	)
	(segment
		(start 31.876746 -289.966654)
		(end 30.771846 -289.966654)
		(width 0.20066)
		(layer "F.Cu")
		(net "M_C_CPU1_SA_DQ<21>")
	)
	(segment
		(start 25.27808 -290.177982)
		(end 25.432512 -290.02355)
		(width 0.20066)
		(layer "F.Cu")
		(net "M_C_CPU1_SA_DQ<21>")
	)
	(segment
		(start 26.2128 -289.541712)
		(end 28.198318 -289.541712)
		(width 0.1016)
		(layer "F.Cu")
		(net "M_C_CPU1_SA_DQ<21>")
	)
	(segment
		(start 92.484194 -266.128246)
		(end 92.484194 -265.592306)
		(width 0.20066)
		(layer "F.Cu")
		(net "M_C_CPU1_SA_DQ<21>")
	)
	(segment
		(start 24.562308 -289.966654)
		(end 24.773636 -290.177982)
		(width 0.20066)
		(layer "F.Cu")
		(net "M_C_CPU1_SA_DQ<21>")
	)
	(segment
		(start 25.432512 -290.02355)
		(end 25.432512 -289.695382)
		(width 0.20066)
		(layer "F.Cu")
		(net "M_C_CPU1_SA_DQ<21>")
	)
	(segment
		(start 26.20391 -289.532822)
		(end 26.2128 -289.541712)
		(width 0.1016)
		(layer "F.Cu")
		(net "M_C_CPU1_SA_DQ<21>")
	)
	(segment
		(start 49.402746 -289.541966)
		(end 46.417992 -289.541966)
		(width 0.18288)
		(layer "In4.Cu")
		(net "M_C_CPU1_SA_DQ<21>")
	)
	(segment
		(start 45.38853 -288.512504)
		(end 44.438316 -288.512504)
		(width 0.18288)
		(layer "In4.Cu")
		(net "M_C_CPU1_SA_DQ<21>")
	)
	(segment
		(start 89.855802 -265.80592)
		(end 89.852246 -265.803634)
		(width 0.088646)
		(layer "In4.Cu")
		(net "M_C_CPU1_SA_DQ<21>")
	)
	(segment
		(start 83.61299 -266.010898)
		(end 83.61299 -266.444476)
		(width 0.088646)
		(layer "In4.Cu")
		(net "M_C_CPU1_SA_DQ<21>")
	)
	(segment
		(start 40.599106 -288.833306)
		(end 39.8907 -289.541712)
		(width 0.18288)
		(layer "In4.Cu")
		(net "M_C_CPU1_SA_DQ<21>")
	)
	(segment
		(start 83.760818 -265.86307)
		(end 83.61299 -266.010898)
		(width 0.088646)
		(layer "In4.Cu")
		(net "M_C_CPU1_SA_DQ<21>")
	)
	(segment
		(start 34.91611 -289.358832)
		(end 34.91611 -288.990278)
		(width 0.18288)
		(layer "In4.Cu")
		(net "M_C_CPU1_SA_DQ<21>")
	)
	(segment
		(start 81.025746 -267.01242)
		(end 69.501512 -278.536654)
		(width 0.18288)
		(layer "In4.Cu")
		(net "M_C_CPU1_SA_DQ<21>")
	)
	(segment
		(start 44.117514 -288.833306)
		(end 40.599106 -288.833306)
		(width 0.18288)
		(layer "In4.Cu")
		(net "M_C_CPU1_SA_DQ<21>")
	)
	(segment
		(start 90.792046 -265.803634)
		(end 90.786204 -265.800332)
		(width 0.088646)
		(layer "In4.Cu")
		(net "M_C_CPU1_SA_DQ<21>")
	)
	(segment
		(start 34.04235 -289.541712)
		(end 32.301688 -289.541712)
		(width 0.18288)
		(layer "In4.Cu")
		(net "M_C_CPU1_SA_DQ<21>")
	)
	(segment
		(start 34.22523 -289.358832)
		(end 34.04235 -289.541712)
		(width 0.18288)
		(layer "In4.Cu")
		(net "M_C_CPU1_SA_DQ<21>")
	)
	(segment
		(start 59.017408 -287.104836)
		(end 58.16092 -287.104836)
		(width 0.18288)
		(layer "In4.Cu")
		(net "M_C_CPU1_SA_DQ<21>")
	)
	(segment
		(start 82.784188 -267.01242)
		(end 81.025746 -267.01242)
		(width 0.18288)
		(layer "In4.Cu")
		(net "M_C_CPU1_SA_DQ<21>")
	)
	(segment
		(start 90.797888 -265.80719)
		(end 90.792046 -265.803634)
		(width 0.088646)
		(layer "In4.Cu")
		(net "M_C_CPU1_SA_DQ<21>")
	)
	(segment
		(start 88.917018 -265.806428)
		(end 88.912446 -265.803634)
		(width 0.088646)
		(layer "In4.Cu")
		(net "M_C_CPU1_SA_DQ<21>")
	)
	(segment
		(start 44.438316 -288.512504)
		(end 44.117514 -288.833306)
		(width 0.18288)
		(layer "In4.Cu")
		(net "M_C_CPU1_SA_DQ<21>")
	)
	(segment
		(start 60.515246 -286.405066)
		(end 60.015374 -286.904938)
		(width 0.18288)
		(layer "In4.Cu")
		(net "M_C_CPU1_SA_DQ<21>")
	)
	(segment
		(start 58.16092 -287.104836)
		(end 57.396634 -287.869122)
		(width 0.18288)
		(layer "In4.Cu")
		(net "M_C_CPU1_SA_DQ<21>")
	)
	(segment
		(start 88.537796 -265.803634)
		(end 88.537796 -265.803888)
		(width 0.088646)
		(layer "In4.Cu")
		(net "M_C_CPU1_SA_DQ<21>")
	)
	(segment
		(start 35.09899 -289.541712)
		(end 34.91611 -289.358832)
		(width 0.18288)
		(layer "In4.Cu")
		(net "M_C_CPU1_SA_DQ<21>")
	)
	(segment
		(start 63.970154 -285.378652)
		(end 63.38824 -285.378652)
		(width 0.18288)
		(layer "In4.Cu")
		(net "M_C_CPU1_SA_DQ<21>")
	)
	(segment
		(start 62.361826 -286.405066)
		(end 60.515246 -286.405066)
		(width 0.18288)
		(layer "In4.Cu")
		(net "M_C_CPU1_SA_DQ<21>")
	)
	(segment
		(start 83.61299 -266.444476)
		(end 83.045046 -267.01242)
		(width 0.088646)
		(layer "In4.Cu")
		(net "M_C_CPU1_SA_DQ<21>")
	)
	(segment
		(start 55.736236 -289.392614)
		(end 55.03545 -288.691828)
		(width 0.18288)
		(layer "In4.Cu")
		(net "M_C_CPU1_SA_DQ<21>")
	)
	(segment
		(start 39.8907 -289.541712)
		(end 35.09899 -289.541712)
		(width 0.18288)
		(layer "In4.Cu")
		(net "M_C_CPU1_SA_DQ<21>")
	)
	(segment
		(start 60.015374 -286.904938)
		(end 59.217306 -286.904938)
		(width 0.18288)
		(layer "In4.Cu")
		(net "M_C_CPU1_SA_DQ<21>")
	)
	(segment
		(start 34.91611 -288.990278)
		(end 34.73323 -288.807398)
		(width 0.18288)
		(layer "In4.Cu")
		(net "M_C_CPU1_SA_DQ<21>")
	)
	(segment
		(start 34.22523 -288.990278)
		(end 34.22523 -289.358832)
		(width 0.18288)
		(layer "In4.Cu")
		(net "M_C_CPU1_SA_DQ<21>")
	)
	(segment
		(start 57.396634 -288.40303)
		(end 56.40705 -289.392614)
		(width 0.18288)
		(layer "In4.Cu")
		(net "M_C_CPU1_SA_DQ<21>")
	)
	(segment
		(start 57.396634 -287.869122)
		(end 57.396634 -288.40303)
		(width 0.18288)
		(layer "In4.Cu")
		(net "M_C_CPU1_SA_DQ<21>")
	)
	(segment
		(start 32.301688 -289.541712)
		(end 31.876746 -289.966654)
		(width 0.18288)
		(layer "In4.Cu")
		(net "M_C_CPU1_SA_DQ<21>")
	)
	(segment
		(start 88.912446 -265.803634)
		(end 88.906604 -265.800332)
		(width 0.088646)
		(layer "In4.Cu")
		(net "M_C_CPU1_SA_DQ<21>")
	)
	(segment
		(start 34.40811 -288.807398)
		(end 34.22523 -288.990278)
		(width 0.18288)
		(layer "In4.Cu")
		(net "M_C_CPU1_SA_DQ<21>")
	)
	(segment
		(start 63.38824 -285.378652)
		(end 62.361826 -286.405066)
		(width 0.18288)
		(layer "In4.Cu")
		(net "M_C_CPU1_SA_DQ<21>")
	)
	(segment
		(start 46.417992 -289.541966)
		(end 45.38853 -288.512504)
		(width 0.18288)
		(layer "In4.Cu")
		(net "M_C_CPU1_SA_DQ<21>")
	)
	(segment
		(start 67.998594 -282.164028)
		(end 66.47434 -283.688282)
		(width 0.18288)
		(layer "In4.Cu")
		(net "M_C_CPU1_SA_DQ<21>")
	)
	(segment
		(start 59.217306 -286.904938)
		(end 59.017408 -287.104836)
		(width 0.18288)
		(layer "In4.Cu")
		(net "M_C_CPU1_SA_DQ<21>")
	)
	(segment
		(start 83.045046 -267.01242)
		(end 82.784188 -267.01242)
		(width 0.088646)
		(layer "In4.Cu")
		(net "M_C_CPU1_SA_DQ<21>")
	)
	(segment
		(start 65.660524 -283.688282)
		(end 63.970154 -285.378652)
		(width 0.18288)
		(layer "In4.Cu")
		(net "M_C_CPU1_SA_DQ<21>")
	)
	(segment
		(start 55.03545 -288.691828)
		(end 50.252884 -288.691828)
		(width 0.18288)
		(layer "In4.Cu")
		(net "M_C_CPU1_SA_DQ<21>")
	)
	(segment
		(start 50.252884 -288.691828)
		(end 49.402746 -289.541966)
		(width 0.18288)
		(layer "In4.Cu")
		(net "M_C_CPU1_SA_DQ<21>")
	)
	(segment
		(start 69.501512 -278.536654)
		(end 67.998594 -282.164028)
		(width 0.18288)
		(layer "In4.Cu")
		(net "M_C_CPU1_SA_DQ<21>")
	)
	(segment
		(start 34.73323 -288.807398)
		(end 34.40811 -288.807398)
		(width 0.18288)
		(layer "In4.Cu")
		(net "M_C_CPU1_SA_DQ<21>")
	)
	(segment
		(start 91.739212 -265.807952)
		(end 91.726004 -265.800332)
		(width 0.088646)
		(layer "In4.Cu")
		(net "M_C_CPU1_SA_DQ<21>")
	)
	(segment
		(start 56.40705 -289.392614)
		(end 55.736236 -289.392614)
		(width 0.18288)
		(layer "In4.Cu")
		(net "M_C_CPU1_SA_DQ<21>")
	)
	(segment
		(start 66.47434 -283.688282)
		(end 65.660524 -283.688282)
		(width 0.18288)
		(layer "In4.Cu")
		(net "M_C_CPU1_SA_DQ<21>")
	)
	(arc
		(start 90.786204 -265.800332)
		(mid 90.601349 -265.753382)
		(end 90.417396 -265.803634)
		(width 0.088646)
		(layer "In4.Cu")
		(net "M_C_CPU1_SA_DQ<21>")
	)
	(arc
		(start 89.477596 -265.803634)
		(mid 89.197682 -265.879403)
		(end 88.917018 -265.806428)
		(width 0.088646)
		(layer "In4.Cu")
		(net "M_C_CPU1_SA_DQ<21>")
	)
	(arc
		(start 90.417396 -265.803634)
		(mid 90.136915 -265.879406)
		(end 89.855802 -265.80592)
		(width 0.088646)
		(layer "In4.Cu")
		(net "M_C_CPU1_SA_DQ<21>")
	)
	(arc
		(start 88.537796 -265.803888)
		(mid 88.255094 -265.87963)
		(end 87.972392 -265.803888)
		(width 0.088646)
		(layer "In4.Cu")
		(net "M_C_CPU1_SA_DQ<21>")
	)
	(arc
		(start 85.152992 -265.803888)
		(mid 84.965794 -265.753745)
		(end 84.778596 -265.803888)
		(width 0.088646)
		(layer "In4.Cu")
		(net "M_C_CPU1_SA_DQ<21>")
	)
	(arc
		(start 87.597996 -265.803888)
		(mid 87.315294 -265.87963)
		(end 87.032592 -265.803888)
		(width 0.088646)
		(layer "In4.Cu")
		(net "M_C_CPU1_SA_DQ<21>")
	)
	(arc
		(start 84.213192 -265.803888)
		(mid 84.025994 -265.753745)
		(end 83.838796 -265.803888)
		(width 0.088646)
		(layer "In4.Cu")
		(net "M_C_CPU1_SA_DQ<21>")
	)
	(arc
		(start 87.032592 -265.803888)
		(mid 86.845394 -265.753745)
		(end 86.658196 -265.803888)
		(width 0.088646)
		(layer "In4.Cu")
		(net "M_C_CPU1_SA_DQ<21>")
	)
	(arc
		(start 85.718396 -265.803888)
		(mid 85.435694 -265.87963)
		(end 85.152992 -265.803888)
		(width 0.088646)
		(layer "In4.Cu")
		(net "M_C_CPU1_SA_DQ<21>")
	)
	(arc
		(start 83.838796 -265.803888)
		(mid 83.797866 -265.830921)
		(end 83.760818 -265.86307)
		(width 0.088646)
		(layer "In4.Cu")
		(net "M_C_CPU1_SA_DQ<21>")
	)
	(arc
		(start 92.484194 -266.128246)
		(mid 92.10039 -265.994413)
		(end 91.739212 -265.807952)
		(width 0.088646)
		(layer "In4.Cu")
		(net "M_C_CPU1_SA_DQ<21>")
	)
	(arc
		(start 84.778596 -265.803888)
		(mid 84.495894 -265.87963)
		(end 84.213192 -265.803888)
		(width 0.088646)
		(layer "In4.Cu")
		(net "M_C_CPU1_SA_DQ<21>")
	)
	(arc
		(start 86.092792 -265.803888)
		(mid 85.905594 -265.753745)
		(end 85.718396 -265.803888)
		(width 0.088646)
		(layer "In4.Cu")
		(net "M_C_CPU1_SA_DQ<21>")
	)
	(arc
		(start 89.852246 -265.803634)
		(mid 89.664938 -265.753525)
		(end 89.477596 -265.803634)
		(width 0.088646)
		(layer "In4.Cu")
		(net "M_C_CPU1_SA_DQ<21>")
	)
	(arc
		(start 86.658196 -265.803888)
		(mid 86.375494 -265.87963)
		(end 86.092792 -265.803888)
		(width 0.088646)
		(layer "In4.Cu")
		(net "M_C_CPU1_SA_DQ<21>")
	)
	(arc
		(start 87.972392 -265.803888)
		(mid 87.785194 -265.753745)
		(end 87.597996 -265.803888)
		(width 0.088646)
		(layer "In4.Cu")
		(net "M_C_CPU1_SA_DQ<21>")
	)
	(arc
		(start 91.726004 -265.800332)
		(mid 91.541149 -265.753382)
		(end 91.357196 -265.803634)
		(width 0.088646)
		(layer "In4.Cu")
		(net "M_C_CPU1_SA_DQ<21>")
	)
	(arc
		(start 91.357196 -265.803634)
		(mid 91.078022 -265.879399)
		(end 90.797888 -265.80719)
		(width 0.088646)
		(layer "In4.Cu")
		(net "M_C_CPU1_SA_DQ<21>")
	)
	(arc
		(start 88.906604 -265.800332)
		(mid 88.721749 -265.753382)
		(end 88.537796 -265.803634)
		(width 0.088646)
		(layer "In4.Cu")
		(net "M_C_CPU1_SA_DQ<21>")
	)
	(segment
		(start 25.259792 -291.905436)
		(end 25.432512 -291.732716)
		(width 0.20066)
		(layer "F.Cu")
		(net "M_C_CPU1_SA_DQ<20>")
	)
	(segment
		(start 92.014294 -266.405868)
		(end 92.014548 -266.406122)
		(width 0.20066)
		(layer "F.Cu")
		(net "M_C_CPU1_SA_DQ<20>")
	)
	(segment
		(start 26.20391 -291.233606)
		(end 26.212038 -291.241734)
		(width 0.101854)
		(layer "F.Cu")
		(net "M_C_CPU1_SA_DQ<20>")
	)
	(segment
		(start 24.801068 -291.905436)
		(end 25.259792 -291.905436)
		(width 0.20066)
		(layer "F.Cu")
		(net "M_C_CPU1_SA_DQ<20>")
	)
	(segment
		(start 25.642062 -291.233606)
		(end 26.20391 -291.233606)
		(width 0.20066)
		(layer "F.Cu")
		(net "M_C_CPU1_SA_DQ<20>")
	)
	(segment
		(start 25.432512 -291.732716)
		(end 25.432512 -291.443156)
		(width 0.20066)
		(layer "F.Cu")
		(net "M_C_CPU1_SA_DQ<20>")
	)
	(segment
		(start 23.228046 -291.666676)
		(end 24.562308 -291.666676)
		(width 0.20066)
		(layer "F.Cu")
		(net "M_C_CPU1_SA_DQ<20>")
	)
	(segment
		(start 26.459942 -291.241734)
		(end 28.529026 -291.241734)
		(width 0.1016)
		(layer "F.Cu")
		(net "M_C_CPU1_SA_DQ<20>")
	)
	(segment
		(start 24.562308 -291.666676)
		(end 24.801068 -291.905436)
		(width 0.20066)
		(layer "F.Cu")
		(net "M_C_CPU1_SA_DQ<20>")
	)
	(segment
		(start 31.876746 -291.666676)
		(end 30.771846 -291.666676)
		(width 0.20066)
		(layer "F.Cu")
		(net "M_C_CPU1_SA_DQ<20>")
	)
	(segment
		(start 28.529026 -291.241734)
		(end 28.977844 -291.241734)
		(width 0.20066)
		(layer "F.Cu")
		(net "M_C_CPU1_SA_DQ<20>")
	)
	(segment
		(start 92.014548 -266.406122)
		(end 92.014548 -266.941808)
		(width 0.20066)
		(layer "F.Cu")
		(net "M_C_CPU1_SA_DQ<20>")
	)
	(segment
		(start 26.212038 -291.241734)
		(end 26.459942 -291.241734)
		(width 0.101854)
		(layer "F.Cu")
		(net "M_C_CPU1_SA_DQ<20>")
	)
	(segment
		(start 28.977844 -291.241734)
		(end 29.402786 -291.666676)
		(width 0.20066)
		(layer "F.Cu")
		(net "M_C_CPU1_SA_DQ<20>")
	)
	(segment
		(start 25.432512 -291.443156)
		(end 25.642062 -291.233606)
		(width 0.20066)
		(layer "F.Cu")
		(net "M_C_CPU1_SA_DQ<20>")
	)
	(segment
		(start 29.402786 -291.666676)
		(end 30.771846 -291.666676)
		(width 0.20066)
		(layer "F.Cu")
		(net "M_C_CPU1_SA_DQ<20>")
	)
	(segment
		(start 41.485566 -290.830508)
		(end 41.07434 -291.241734)
		(width 0.18288)
		(layer "In4.Cu")
		(net "M_C_CPU1_SA_DQ<20>")
	)
	(segment
		(start 82.899504 -268.0081)
		(end 82.784188 -268.0081)
		(width 0.088646)
		(layer "In4.Cu")
		(net "M_C_CPU1_SA_DQ<20>")
	)
	(segment
		(start 41.07434 -291.241734)
		(end 32.301688 -291.241734)
		(width 0.18288)
		(layer "In4.Cu")
		(net "M_C_CPU1_SA_DQ<20>")
	)
	(segment
		(start 55.65521 -291.025834)
		(end 55.021226 -290.39185)
		(width 0.18288)
		(layer "In4.Cu")
		(net "M_C_CPU1_SA_DQ<20>")
	)
	(segment
		(start 60.05195 -288.515298)
		(end 59.779154 -288.515298)
		(width 0.18288)
		(layer "In4.Cu")
		(net "M_C_CPU1_SA_DQ<20>")
	)
	(segment
		(start 62.490858 -287.84804)
		(end 60.719208 -287.84804)
		(width 0.18288)
		(layer "In4.Cu")
		(net "M_C_CPU1_SA_DQ<20>")
	)
	(segment
		(start 53.096414 -290.723828)
		(end 52.764436 -290.39185)
		(width 0.18288)
		(layer "In4.Cu")
		(net "M_C_CPU1_SA_DQ<20>")
	)
	(segment
		(start 60.719208 -287.84804)
		(end 60.05195 -288.515298)
		(width 0.18288)
		(layer "In4.Cu")
		(net "M_C_CPU1_SA_DQ<20>")
	)
	(segment
		(start 42.731436 -291.751258)
		(end 42.406316 -291.751258)
		(width 0.18288)
		(layer "In4.Cu")
		(net "M_C_CPU1_SA_DQ<20>")
	)
	(segment
		(start 64.136524 -286.99079)
		(end 63.348108 -286.99079)
		(width 0.18288)
		(layer "In4.Cu")
		(net "M_C_CPU1_SA_DQ<20>")
	)
	(segment
		(start 68.735702 -283.116528)
		(end 66.461132 -285.391098)
		(width 0.18288)
		(layer "In4.Cu")
		(net "M_C_CPU1_SA_DQ<20>")
	)
	(segment
		(start 59.779154 -288.515298)
		(end 58.783474 -289.510978)
		(width 0.18288)
		(layer "In4.Cu")
		(net "M_C_CPU1_SA_DQ<20>")
	)
	(segment
		(start 82.784188 -268.0081)
		(end 81.458562 -268.0081)
		(width 0.18288)
		(layer "In4.Cu")
		(net "M_C_CPU1_SA_DQ<20>")
	)
	(segment
		(start 32.301688 -291.241734)
		(end 31.876746 -291.666676)
		(width 0.18288)
		(layer "In4.Cu")
		(net "M_C_CPU1_SA_DQ<20>")
	)
	(segment
		(start 45.275246 -290.364418)
		(end 44.411392 -290.364418)
		(width 0.18288)
		(layer "In4.Cu")
		(net "M_C_CPU1_SA_DQ<20>")
	)
	(segment
		(start 56.785764 -291.025834)
		(end 55.65521 -291.025834)
		(width 0.18288)
		(layer "In4.Cu")
		(net "M_C_CPU1_SA_DQ<20>")
	)
	(segment
		(start 42.406316 -291.751258)
		(end 42.223436 -291.568378)
		(width 0.18288)
		(layer "In4.Cu")
		(net "M_C_CPU1_SA_DQ<20>")
	)
	(segment
		(start 63.348108 -286.99079)
		(end 62.490858 -287.84804)
		(width 0.18288)
		(layer "In4.Cu")
		(net "M_C_CPU1_SA_DQ<20>")
	)
	(segment
		(start 44.411392 -290.364418)
		(end 43.945302 -290.830508)
		(width 0.18288)
		(layer "In4.Cu")
		(net "M_C_CPU1_SA_DQ<20>")
	)
	(segment
		(start 42.223436 -291.568378)
		(end 42.223436 -291.013388)
		(width 0.18288)
		(layer "In4.Cu")
		(net "M_C_CPU1_SA_DQ<20>")
	)
	(segment
		(start 42.914316 -291.013388)
		(end 42.914316 -291.568378)
		(width 0.18288)
		(layer "In4.Cu")
		(net "M_C_CPU1_SA_DQ<20>")
	)
	(segment
		(start 89.012014 -266.61491)
		(end 89.007696 -266.617704)
		(width 0.088646)
		(layer "In4.Cu")
		(net "M_C_CPU1_SA_DQ<20>")
	)
	(segment
		(start 43.945302 -290.830508)
		(end 43.097196 -290.830508)
		(width 0.18288)
		(layer "In4.Cu")
		(net "M_C_CPU1_SA_DQ<20>")
	)
	(segment
		(start 84.230718 -266.676886)
		(end 82.899504 -268.0081)
		(width 0.088646)
		(layer "In4.Cu")
		(net "M_C_CPU1_SA_DQ<20>")
	)
	(segment
		(start 52.764436 -290.39185)
		(end 50.190146 -290.39185)
		(width 0.18288)
		(layer "In4.Cu")
		(net "M_C_CPU1_SA_DQ<20>")
	)
	(segment
		(start 50.190146 -290.39185)
		(end 49.340008 -291.241988)
		(width 0.18288)
		(layer "In4.Cu")
		(net "M_C_CPU1_SA_DQ<20>")
	)
	(segment
		(start 43.097196 -290.830508)
		(end 42.914316 -291.013388)
		(width 0.18288)
		(layer "In4.Cu")
		(net "M_C_CPU1_SA_DQ<20>")
	)
	(segment
		(start 55.021226 -290.39185)
		(end 53.821076 -290.39185)
		(width 0.18288)
		(layer "In4.Cu")
		(net "M_C_CPU1_SA_DQ<20>")
	)
	(segment
		(start 89.382092 -266.617704)
		(end 89.382346 -266.61745)
		(width 0.088646)
		(layer "In4.Cu")
		(net "M_C_CPU1_SA_DQ<20>")
	)
	(segment
		(start 70.423786 -279.042876)
		(end 68.735702 -283.116528)
		(width 0.18288)
		(layer "In4.Cu")
		(net "M_C_CPU1_SA_DQ<20>")
	)
	(segment
		(start 65.736216 -285.391098)
		(end 64.136524 -286.99079)
		(width 0.18288)
		(layer "In4.Cu")
		(net "M_C_CPU1_SA_DQ<20>")
	)
	(segment
		(start 58.783474 -289.510978)
		(end 58.30062 -289.510978)
		(width 0.18288)
		(layer "In4.Cu")
		(net "M_C_CPU1_SA_DQ<20>")
	)
	(segment
		(start 91.658186 -266.846304)
		(end 91.261946 -266.61745)
		(width 0.088646)
		(layer "In4.Cu")
		(net "M_C_CPU1_SA_DQ<20>")
	)
	(segment
		(start 53.821076 -290.39185)
		(end 53.489098 -290.723828)
		(width 0.18288)
		(layer "In4.Cu")
		(net "M_C_CPU1_SA_DQ<20>")
	)
	(segment
		(start 42.223436 -291.013388)
		(end 42.040556 -290.830508)
		(width 0.18288)
		(layer "In4.Cu")
		(net "M_C_CPU1_SA_DQ<20>")
	)
	(segment
		(start 53.489098 -290.723828)
		(end 53.096414 -290.723828)
		(width 0.18288)
		(layer "In4.Cu")
		(net "M_C_CPU1_SA_DQ<20>")
	)
	(segment
		(start 84.230718 -266.676632)
		(end 84.230718 -266.676886)
		(width 0.088646)
		(layer "In4.Cu")
		(net "M_C_CPU1_SA_DQ<20>")
	)
	(segment
		(start 46.152816 -291.241988)
		(end 45.275246 -290.364418)
		(width 0.18288)
		(layer "In4.Cu")
		(net "M_C_CPU1_SA_DQ<20>")
	)
	(segment
		(start 58.30062 -289.510978)
		(end 56.785764 -291.025834)
		(width 0.18288)
		(layer "In4.Cu")
		(net "M_C_CPU1_SA_DQ<20>")
	)
	(segment
		(start 42.914316 -291.568378)
		(end 42.731436 -291.751258)
		(width 0.18288)
		(layer "In4.Cu")
		(net "M_C_CPU1_SA_DQ<20>")
	)
	(segment
		(start 42.040556 -290.830508)
		(end 41.485566 -290.830508)
		(width 0.18288)
		(layer "In4.Cu")
		(net "M_C_CPU1_SA_DQ<20>")
	)
	(segment
		(start 90.893138 -266.614148)
		(end 90.887296 -266.617704)
		(width 0.088646)
		(layer "In4.Cu")
		(net "M_C_CPU1_SA_DQ<20>")
	)
	(segment
		(start 81.458562 -268.0081)
		(end 70.423786 -279.042876)
		(width 0.18288)
		(layer "In4.Cu")
		(net "M_C_CPU1_SA_DQ<20>")
	)
	(segment
		(start 49.340008 -291.241988)
		(end 46.152816 -291.241988)
		(width 0.18288)
		(layer "In4.Cu")
		(net "M_C_CPU1_SA_DQ<20>")
	)
	(segment
		(start 66.461132 -285.391098)
		(end 65.736216 -285.391098)
		(width 0.18288)
		(layer "In4.Cu")
		(net "M_C_CPU1_SA_DQ<20>")
	)
	(arc
		(start 86.188296 -266.617704)
		(mid 85.905594 -266.69348)
		(end 85.622892 -266.617704)
		(width 0.088646)
		(layer "In4.Cu")
		(net "M_C_CPU1_SA_DQ<20>")
	)
	(arc
		(start 89.007696 -266.617704)
		(mid 88.724994 -266.69348)
		(end 88.442292 -266.617704)
		(width 0.088646)
		(layer "In4.Cu")
		(net "M_C_CPU1_SA_DQ<20>")
	)
	(arc
		(start 91.261946 -266.61745)
		(mid 91.077992 -266.567321)
		(end 90.893138 -266.614148)
		(width 0.088646)
		(layer "In4.Cu")
		(net "M_C_CPU1_SA_DQ<20>")
	)
	(arc
		(start 88.067896 -266.617704)
		(mid 87.785194 -266.69348)
		(end 87.502492 -266.617704)
		(width 0.088646)
		(layer "In4.Cu")
		(net "M_C_CPU1_SA_DQ<20>")
	)
	(arc
		(start 90.887296 -266.617704)
		(mid 90.604594 -266.69348)
		(end 90.321892 -266.617704)
		(width 0.088646)
		(layer "In4.Cu")
		(net "M_C_CPU1_SA_DQ<20>")
	)
	(arc
		(start 87.502492 -266.617704)
		(mid 87.315294 -266.567527)
		(end 87.128096 -266.617704)
		(width 0.088646)
		(layer "In4.Cu")
		(net "M_C_CPU1_SA_DQ<20>")
	)
	(arc
		(start 86.562692 -266.617704)
		(mid 86.375494 -266.567527)
		(end 86.188296 -266.617704)
		(width 0.088646)
		(layer "In4.Cu")
		(net "M_C_CPU1_SA_DQ<20>")
	)
	(arc
		(start 89.947496 -266.617704)
		(mid 89.664794 -266.69348)
		(end 89.382092 -266.617704)
		(width 0.088646)
		(layer "In4.Cu")
		(net "M_C_CPU1_SA_DQ<20>")
	)
	(arc
		(start 84.308696 -266.617704)
		(mid 84.26777 -266.644606)
		(end 84.230718 -266.676632)
		(width 0.088646)
		(layer "In4.Cu")
		(net "M_C_CPU1_SA_DQ<20>")
	)
	(arc
		(start 84.683092 -266.617704)
		(mid 84.495894 -266.567527)
		(end 84.308696 -266.617704)
		(width 0.088646)
		(layer "In4.Cu")
		(net "M_C_CPU1_SA_DQ<20>")
	)
	(arc
		(start 92.014548 -266.941808)
		(mid 91.830065 -266.917559)
		(end 91.658186 -266.846304)
		(width 0.088646)
		(layer "In4.Cu")
		(net "M_C_CPU1_SA_DQ<20>")
	)
	(arc
		(start 87.128096 -266.617704)
		(mid 86.845394 -266.69348)
		(end 86.562692 -266.617704)
		(width 0.088646)
		(layer "In4.Cu")
		(net "M_C_CPU1_SA_DQ<20>")
	)
	(arc
		(start 88.442292 -266.617704)
		(mid 88.255094 -266.567527)
		(end 88.067896 -266.617704)
		(width 0.088646)
		(layer "In4.Cu")
		(net "M_C_CPU1_SA_DQ<20>")
	)
	(arc
		(start 89.382346 -266.61745)
		(mid 89.197509 -266.567189)
		(end 89.012014 -266.61491)
		(width 0.088646)
		(layer "In4.Cu")
		(net "M_C_CPU1_SA_DQ<20>")
	)
	(arc
		(start 85.248496 -266.617704)
		(mid 84.965794 -266.69348)
		(end 84.683092 -266.617704)
		(width 0.088646)
		(layer "In4.Cu")
		(net "M_C_CPU1_SA_DQ<20>")
	)
	(arc
		(start 90.321892 -266.617704)
		(mid 90.134694 -266.567527)
		(end 89.947496 -266.617704)
		(width 0.088646)
		(layer "In4.Cu")
		(net "M_C_CPU1_SA_DQ<20>")
	)
	(arc
		(start 85.622892 -266.617704)
		(mid 85.435694 -266.567527)
		(end 85.248496 -266.617704)
		(width 0.088646)
		(layer "In4.Cu")
		(net "M_C_CPU1_SA_DQ<20>")
	)
	(segment
		(start 24.562308 -314.616592)
		(end 24.773636 -314.82792)
		(width 0.20066)
		(layer "F.Cu")
		(net "M_C_CPU1_SA_DQ<1>")
	)
	(segment
		(start 24.773636 -314.82792)
		(end 25.27808 -314.82792)
		(width 0.20066)
		(layer "F.Cu")
		(net "M_C_CPU1_SA_DQ<1>")
	)
	(segment
		(start 28.529026 -314.19165)
		(end 28.707588 -314.19165)
		(width 0.20066)
		(layer "F.Cu")
		(net "M_C_CPU1_SA_DQ<1>")
	)
	(segment
		(start 25.432512 -314.673488)
		(end 25.432512 -314.34532)
		(width 0.20066)
		(layer "F.Cu")
		(net "M_C_CPU1_SA_DQ<1>")
	)
	(segment
		(start 92.014294 -278.336248)
		(end 92.014548 -278.336502)
		(width 0.20066)
		(layer "F.Cu")
		(net "M_C_CPU1_SA_DQ<1>")
	)
	(segment
		(start 28.707588 -314.19165)
		(end 29.13253 -314.616592)
		(width 0.20066)
		(layer "F.Cu")
		(net "M_C_CPU1_SA_DQ<1>")
	)
	(segment
		(start 26.2128 -314.19165)
		(end 28.198318 -314.19165)
		(width 0.1016)
		(layer "F.Cu")
		(net "M_C_CPU1_SA_DQ<1>")
	)
	(segment
		(start 23.228046 -314.616592)
		(end 24.562308 -314.616592)
		(width 0.20066)
		(layer "F.Cu")
		(net "M_C_CPU1_SA_DQ<1>")
	)
	(segment
		(start 28.198318 -314.19165)
		(end 28.529026 -314.19165)
		(width 0.101854)
		(layer "F.Cu")
		(net "M_C_CPU1_SA_DQ<1>")
	)
	(segment
		(start 25.432512 -314.34532)
		(end 25.595072 -314.18276)
		(width 0.20066)
		(layer "F.Cu")
		(net "M_C_CPU1_SA_DQ<1>")
	)
	(segment
		(start 92.014294 -277.800562)
		(end 92.014294 -278.336248)
		(width 0.20066)
		(layer "F.Cu")
		(net "M_C_CPU1_SA_DQ<1>")
	)
	(segment
		(start 31.876746 -314.616592)
		(end 30.771846 -314.616592)
		(width 0.20066)
		(layer "F.Cu")
		(net "M_C_CPU1_SA_DQ<1>")
	)
	(segment
		(start 29.13253 -314.616592)
		(end 30.771846 -314.616592)
		(width 0.20066)
		(layer "F.Cu")
		(net "M_C_CPU1_SA_DQ<1>")
	)
	(segment
		(start 25.595072 -314.18276)
		(end 26.20391 -314.18276)
		(width 0.20066)
		(layer "F.Cu")
		(net "M_C_CPU1_SA_DQ<1>")
	)
	(segment
		(start 26.20391 -314.18276)
		(end 26.2128 -314.19165)
		(width 0.1016)
		(layer "F.Cu")
		(net "M_C_CPU1_SA_DQ<1>")
	)
	(segment
		(start 25.27808 -314.82792)
		(end 25.432512 -314.673488)
		(width 0.20066)
		(layer "F.Cu")
		(net "M_C_CPU1_SA_DQ<1>")
	)
	(segment
		(start 55.746396 -315.741304)
		(end 54.870604 -316.617096)
		(width 0.18288)
		(layer "In4.Cu")
		(net "M_C_CPU1_SA_DQ<1>")
	)
	(segment
		(start 39.693088 -315.041788)
		(end 32.301942 -315.041788)
		(width 0.18288)
		(layer "In4.Cu")
		(net "M_C_CPU1_SA_DQ<1>")
	)
	(segment
		(start 91.369388 -278.818848)
		(end 91.357196 -278.82596)
		(width 0.088646)
		(layer "In4.Cu")
		(net "M_C_CPU1_SA_DQ<1>")
	)
	(segment
		(start 91.169744 -280.778204)
		(end 91.169744 -280.793698)
		(width 0.088646)
		(layer "In4.Cu")
		(net "M_C_CPU1_SA_DQ<1>")
	)
	(segment
		(start 40.526716 -316.211712)
		(end 40.526716 -315.875416)
		(width 0.18288)
		(layer "In4.Cu")
		(net "M_C_CPU1_SA_DQ<1>")
	)
	(segment
		(start 52.173124 -316.617096)
		(end 51.698652 -317.091568)
		(width 0.18288)
		(layer "In4.Cu")
		(net "M_C_CPU1_SA_DQ<1>")
	)
	(segment
		(start 85.640672 -287.024318)
		(end 85.115654 -287.549336)
		(width 0.088646)
		(layer "In4.Cu")
		(net "M_C_CPU1_SA_DQ<1>")
	)
	(segment
		(start 88.350344 -285.661354)
		(end 88.350344 -285.679896)
		(width 0.088646)
		(layer "In4.Cu")
		(net "M_C_CPU1_SA_DQ<1>")
	)
	(segment
		(start 91.357196 -279.474676)
		(end 91.363292 -279.478232)
		(width 0.088646)
		(layer "In4.Cu")
		(net "M_C_CPU1_SA_DQ<1>")
	)
	(segment
		(start 59.760612 -316.007496)
		(end 58.930032 -315.176916)
		(width 0.18288)
		(layer "In4.Cu")
		(net "M_C_CPU1_SA_DQ<1>")
	)
	(segment
		(start 90.887296 -281.916378)
		(end 90.893392 -281.919934)
		(width 0.088646)
		(layer "In4.Cu")
		(net "M_C_CPU1_SA_DQ<1>")
	)
	(segment
		(start 65.000632 -314.06592)
		(end 63.368682 -314.06592)
		(width 0.18288)
		(layer "In4.Cu")
		(net "M_C_CPU1_SA_DQ<1>")
	)
	(segment
		(start 89.01049 -284.521656)
		(end 89.007696 -284.52318)
		(width 0.088646)
		(layer "In4.Cu")
		(net "M_C_CPU1_SA_DQ<1>")
	)
	(segment
		(start 40.526716 -315.875416)
		(end 39.693088 -315.041788)
		(width 0.18288)
		(layer "In4.Cu")
		(net "M_C_CPU1_SA_DQ<1>")
	)
	(segment
		(start 79.735934 -298.096178)
		(end 73.058274 -304.773838)
		(width 0.18288)
		(layer "In4.Cu")
		(net "M_C_CPU1_SA_DQ<1>")
	)
	(segment
		(start 61.19495 -314.96635)
		(end 60.153804 -316.007496)
		(width 0.18288)
		(layer "In4.Cu")
		(net "M_C_CPU1_SA_DQ<1>")
	)
	(segment
		(start 92.014548 -278.336502)
		(end 91.672664 -278.626824)
		(width 0.088646)
		(layer "In4.Cu")
		(net "M_C_CPU1_SA_DQ<1>")
	)
	(segment
		(start 89.290398 -284.025086)
		(end 89.290398 -284.033722)
		(width 0.088646)
		(layer "In4.Cu")
		(net "M_C_CPU1_SA_DQ<1>")
	)
	(segment
		(start 41.058846 -316.743842)
		(end 40.526716 -316.211712)
		(width 0.18288)
		(layer "In4.Cu")
		(net "M_C_CPU1_SA_DQ<1>")
	)
	(segment
		(start 73.058274 -306.848764)
		(end 66.517012 -313.390026)
		(width 0.18288)
		(layer "In4.Cu")
		(net "M_C_CPU1_SA_DQ<1>")
	)
	(segment
		(start 51.538632 -317.591694)
		(end 46.220126 -317.591694)
		(width 0.18288)
		(layer "In4.Cu")
		(net "M_C_CPU1_SA_DQ<1>")
	)
	(segment
		(start 90.8812 -282.899104)
		(end 90.87866 -282.900628)
		(width 0.088646)
		(layer "In4.Cu")
		(net "M_C_CPU1_SA_DQ<1>")
	)
	(segment
		(start 90.88755 -281.267662)
		(end 90.887296 -281.267662)
		(width 0.088646)
		(layer "In4.Cu")
		(net "M_C_CPU1_SA_DQ<1>")
	)
	(segment
		(start 90.878406 -281.911298)
		(end 90.887296 -281.916378)
		(width 0.088646)
		(layer "In4.Cu")
		(net "M_C_CPU1_SA_DQ<1>")
	)
	(segment
		(start 84.944458 -287.549336)
		(end 84.84997 -287.549336)
		(width 0.18288)
		(layer "In4.Cu")
		(net "M_C_CPU1_SA_DQ<1>")
	)
	(segment
		(start 54.870604 -316.617096)
		(end 52.173124 -316.617096)
		(width 0.18288)
		(layer "In4.Cu")
		(net "M_C_CPU1_SA_DQ<1>")
	)
	(segment
		(start 32.301942 -315.041788)
		(end 31.876746 -314.616592)
		(width 0.18288)
		(layer "In4.Cu")
		(net "M_C_CPU1_SA_DQ<1>")
	)
	(segment
		(start 91.348306 -279.469596)
		(end 91.357196 -279.474676)
		(width 0.088646)
		(layer "In4.Cu")
		(net "M_C_CPU1_SA_DQ<1>")
	)
	(segment
		(start 46.220126 -317.591694)
		(end 45.372274 -316.743842)
		(width 0.18288)
		(layer "In4.Cu")
		(net "M_C_CPU1_SA_DQ<1>")
	)
	(segment
		(start 91.357196 -278.82596)
		(end 91.348306 -278.83104)
		(width 0.088646)
		(layer "In4.Cu")
		(net "M_C_CPU1_SA_DQ<1>")
	)
	(segment
		(start 88.537796 -285.336996)
		(end 88.528906 -285.342076)
		(width 0.088646)
		(layer "In4.Cu")
		(net "M_C_CPU1_SA_DQ<1>")
	)
	(segment
		(start 66.517012 -313.390026)
		(end 65.676526 -313.390026)
		(width 0.18288)
		(layer "In4.Cu")
		(net "M_C_CPU1_SA_DQ<1>")
	)
	(segment
		(start 58.930032 -315.176916)
		(end 57.496964 -315.176916)
		(width 0.18288)
		(layer "In4.Cu")
		(net "M_C_CPU1_SA_DQ<1>")
	)
	(segment
		(start 85.115654 -287.549336)
		(end 84.944458 -287.549336)
		(width 0.088646)
		(layer "In4.Cu")
		(net "M_C_CPU1_SA_DQ<1>")
	)
	(segment
		(start 91.570048 -278.640032)
		(end 91.490038 -278.720042)
		(width 0.088646)
		(layer "In4.Cu")
		(net "M_C_CPU1_SA_DQ<1>")
	)
	(segment
		(start 51.698652 -317.091568)
		(end 51.698652 -317.431674)
		(width 0.18288)
		(layer "In4.Cu")
		(net "M_C_CPU1_SA_DQ<1>")
	)
	(segment
		(start 86.188296 -286.151066)
		(end 86.179406 -286.156146)
		(width 0.088646)
		(layer "In4.Cu")
		(net "M_C_CPU1_SA_DQ<1>")
	)
	(segment
		(start 91.672664 -278.626824)
		(end 91.659456 -278.640032)
		(width 0.088646)
		(layer "In4.Cu")
		(net "M_C_CPU1_SA_DQ<1>")
	)
	(segment
		(start 90.429588 -283.702252)
		(end 90.417396 -283.709364)
		(width 0.088646)
		(layer "In4.Cu")
		(net "M_C_CPU1_SA_DQ<1>")
	)
	(segment
		(start 65.676526 -313.390026)
		(end 65.000632 -314.06592)
		(width 0.18288)
		(layer "In4.Cu")
		(net "M_C_CPU1_SA_DQ<1>")
	)
	(segment
		(start 51.698652 -317.431674)
		(end 51.538632 -317.591694)
		(width 0.18288)
		(layer "In4.Cu")
		(net "M_C_CPU1_SA_DQ<1>")
	)
	(segment
		(start 89.013792 -284.519624)
		(end 89.01049 -284.521656)
		(width 0.088646)
		(layer "In4.Cu")
		(net "M_C_CPU1_SA_DQ<1>")
	)
	(segment
		(start 73.058274 -304.773838)
		(end 73.058274 -306.848764)
		(width 0.18288)
		(layer "In4.Cu")
		(net "M_C_CPU1_SA_DQ<1>")
	)
	(segment
		(start 88.820244 -284.847538)
		(end 88.820244 -284.857444)
		(width 0.088646)
		(layer "In4.Cu")
		(net "M_C_CPU1_SA_DQ<1>")
	)
	(segment
		(start 45.372274 -316.743842)
		(end 41.058846 -316.743842)
		(width 0.18288)
		(layer "In4.Cu")
		(net "M_C_CPU1_SA_DQ<1>")
	)
	(segment
		(start 57.496964 -315.176916)
		(end 56.932576 -315.741304)
		(width 0.18288)
		(layer "In4.Cu")
		(net "M_C_CPU1_SA_DQ<1>")
	)
	(segment
		(start 84.84997 -287.549336)
		(end 83.579462 -288.819844)
		(width 0.18288)
		(layer "In4.Cu")
		(net "M_C_CPU1_SA_DQ<1>")
	)
	(segment
		(start 63.368682 -314.06592)
		(end 61.19495 -314.96635)
		(width 0.18288)
		(layer "In4.Cu")
		(net "M_C_CPU1_SA_DQ<1>")
	)
	(segment
		(start 91.659456 -278.640032)
		(end 91.570048 -278.640032)
		(width 0.088646)
		(layer "In4.Cu")
		(net "M_C_CPU1_SA_DQ<1>")
	)
	(segment
		(start 56.932576 -315.741304)
		(end 55.746396 -315.741304)
		(width 0.18288)
		(layer "In4.Cu")
		(net "M_C_CPU1_SA_DQ<1>")
	)
	(segment
		(start 90.887296 -282.895548)
		(end 90.8812 -282.899104)
		(width 0.088646)
		(layer "In4.Cu")
		(net "M_C_CPU1_SA_DQ<1>")
	)
	(segment
		(start 91.169998 -282.405836)
		(end 91.169998 -282.42006)
		(width 0.088646)
		(layer "In4.Cu")
		(net "M_C_CPU1_SA_DQ<1>")
	)
	(segment
		(start 91.639898 -279.964134)
		(end 91.639898 -279.978358)
		(width 0.088646)
		(layer "In4.Cu")
		(net "M_C_CPU1_SA_DQ<1>")
	)
	(segment
		(start 89.007696 -284.52318)
		(end 88.998806 -284.52826)
		(width 0.088646)
		(layer "In4.Cu")
		(net "M_C_CPU1_SA_DQ<1>")
	)
	(segment
		(start 86.000844 -286.475424)
		(end 86.000844 -286.48533)
		(width 0.088646)
		(layer "In4.Cu")
		(net "M_C_CPU1_SA_DQ<1>")
	)
	(segment
		(start 90.887296 -281.267662)
		(end 90.878406 -281.272742)
		(width 0.088646)
		(layer "In4.Cu")
		(net "M_C_CPU1_SA_DQ<1>")
	)
	(segment
		(start 60.153804 -316.007496)
		(end 59.760612 -316.007496)
		(width 0.18288)
		(layer "In4.Cu")
		(net "M_C_CPU1_SA_DQ<1>")
	)
	(segment
		(start 91.357196 -280.453846)
		(end 91.348306 -280.458926)
		(width 0.088646)
		(layer "In4.Cu")
		(net "M_C_CPU1_SA_DQ<1>")
	)
	(segment
		(start 83.579462 -288.819844)
		(end 79.735934 -298.096178)
		(width 0.18288)
		(layer "In4.Cu")
		(net "M_C_CPU1_SA_DQ<1>")
	)
	(arc
		(start 90.893392 -281.919934)
		(mid 91.095979 -282.126285)
		(end 91.169998 -282.405836)
		(width 0.088646)
		(layer "In4.Cu")
		(net "M_C_CPU1_SA_DQ<1>")
	)
	(arc
		(start 90.87866 -282.900628)
		(mid 90.747746 -283.036988)
		(end 90.700098 -283.219906)
		(width 0.088646)
		(layer "In4.Cu")
		(net "M_C_CPU1_SA_DQ<1>")
	)
	(arc
		(start 89.477596 -283.709364)
		(mid 89.342663 -283.842718)
		(end 89.290398 -284.025086)
		(width 0.088646)
		(layer "In4.Cu")
		(net "M_C_CPU1_SA_DQ<1>")
	)
	(arc
		(start 89.290398 -284.033722)
		(mid 89.216407 -284.313288)
		(end 89.013792 -284.519624)
		(width 0.088646)
		(layer "In4.Cu")
		(net "M_C_CPU1_SA_DQ<1>")
	)
	(arc
		(start 85.718396 -286.964882)
		(mid 85.677587 -286.992054)
		(end 85.640672 -287.024318)
		(width 0.088646)
		(layer "In4.Cu")
		(net "M_C_CPU1_SA_DQ<1>")
	)
	(arc
		(start 87.128096 -286.151066)
		(mid 86.845394 -286.226808)
		(end 86.562692 -286.151066)
		(width 0.088646)
		(layer "In4.Cu")
		(net "M_C_CPU1_SA_DQ<1>")
	)
	(arc
		(start 86.000844 -286.48533)
		(mid 85.922733 -286.762279)
		(end 85.718396 -286.964882)
		(width 0.088646)
		(layer "In4.Cu")
		(net "M_C_CPU1_SA_DQ<1>")
	)
	(arc
		(start 91.169744 -280.793698)
		(mid 91.090374 -281.067432)
		(end 90.88755 -281.267662)
		(width 0.088646)
		(layer "In4.Cu")
		(net "M_C_CPU1_SA_DQ<1>")
	)
	(arc
		(start 87.502492 -286.151066)
		(mid 87.315294 -286.100923)
		(end 87.128096 -286.151066)
		(width 0.088646)
		(layer "In4.Cu")
		(net "M_C_CPU1_SA_DQ<1>")
	)
	(arc
		(start 90.417396 -283.709364)
		(mid 90.134694 -283.78514)
		(end 89.851992 -283.709364)
		(width 0.088646)
		(layer "In4.Cu")
		(net "M_C_CPU1_SA_DQ<1>")
	)
	(arc
		(start 88.998806 -284.52826)
		(mid 88.867892 -284.66462)
		(end 88.820244 -284.847538)
		(width 0.088646)
		(layer "In4.Cu")
		(net "M_C_CPU1_SA_DQ<1>")
	)
	(arc
		(start 90.878406 -281.272742)
		(mid 90.699809 -281.59202)
		(end 90.878406 -281.911298)
		(width 0.088646)
		(layer "In4.Cu")
		(net "M_C_CPU1_SA_DQ<1>")
	)
	(arc
		(start 91.348306 -278.83104)
		(mid 91.169709 -279.150318)
		(end 91.348306 -279.469596)
		(width 0.088646)
		(layer "In4.Cu")
		(net "M_C_CPU1_SA_DQ<1>")
	)
	(arc
		(start 86.562692 -286.151066)
		(mid 86.375494 -286.100923)
		(end 86.188296 -286.151066)
		(width 0.088646)
		(layer "In4.Cu")
		(net "M_C_CPU1_SA_DQ<1>")
	)
	(arc
		(start 88.350344 -285.679896)
		(mid 88.270182 -285.952085)
		(end 88.067896 -286.151066)
		(width 0.088646)
		(layer "In4.Cu")
		(net "M_C_CPU1_SA_DQ<1>")
	)
	(arc
		(start 91.348306 -280.458926)
		(mid 91.217392 -280.595286)
		(end 91.169744 -280.778204)
		(width 0.088646)
		(layer "In4.Cu")
		(net "M_C_CPU1_SA_DQ<1>")
	)
	(arc
		(start 89.851992 -283.709364)
		(mid 89.664794 -283.659221)
		(end 89.477596 -283.709364)
		(width 0.088646)
		(layer "In4.Cu")
		(net "M_C_CPU1_SA_DQ<1>")
	)
	(arc
		(start 88.820244 -284.857444)
		(mid 88.742133 -285.134393)
		(end 88.537796 -285.336996)
		(width 0.088646)
		(layer "In4.Cu")
		(net "M_C_CPU1_SA_DQ<1>")
	)
	(arc
		(start 91.363292 -279.478232)
		(mid 91.565879 -279.684583)
		(end 91.639898 -279.964134)
		(width 0.088646)
		(layer "In4.Cu")
		(net "M_C_CPU1_SA_DQ<1>")
	)
	(arc
		(start 91.639898 -279.978358)
		(mid 91.560679 -280.253043)
		(end 91.357196 -280.453846)
		(width 0.088646)
		(layer "In4.Cu")
		(net "M_C_CPU1_SA_DQ<1>")
	)
	(arc
		(start 88.067896 -286.151066)
		(mid 87.785194 -286.226808)
		(end 87.502492 -286.151066)
		(width 0.088646)
		(layer "In4.Cu")
		(net "M_C_CPU1_SA_DQ<1>")
	)
	(arc
		(start 91.490038 -278.720042)
		(mid 91.433133 -278.773621)
		(end 91.369388 -278.818848)
		(width 0.088646)
		(layer "In4.Cu")
		(net "M_C_CPU1_SA_DQ<1>")
	)
	(arc
		(start 90.700098 -283.219906)
		(mid 90.627863 -283.49643)
		(end 90.429588 -283.702252)
		(width 0.088646)
		(layer "In4.Cu")
		(net "M_C_CPU1_SA_DQ<1>")
	)
	(arc
		(start 91.169998 -282.42006)
		(mid 91.090779 -282.694745)
		(end 90.887296 -282.895548)
		(width 0.088646)
		(layer "In4.Cu")
		(net "M_C_CPU1_SA_DQ<1>")
	)
	(arc
		(start 86.179406 -286.156146)
		(mid 86.048492 -286.292506)
		(end 86.000844 -286.475424)
		(width 0.088646)
		(layer "In4.Cu")
		(net "M_C_CPU1_SA_DQ<1>")
	)
	(arc
		(start 88.528906 -285.342076)
		(mid 88.397992 -285.478436)
		(end 88.350344 -285.661354)
		(width 0.088646)
		(layer "In4.Cu")
		(net "M_C_CPU1_SA_DQ<1>")
	)
	(segment
		(start 29.661866 -295.491662)
		(end 29.899864 -295.491662)
		(width 0.101854)
		(layer "F.Cu")
		(net "M_C_CPU1_SA_DQ<19>")
	)
	(segment
		(start 32.666178 -295.342564)
		(end 32.666178 -295.190926)
		(width 0.20066)
		(layer "F.Cu")
		(net "M_C_CPU1_SA_DQ<19>")
	)
	(segment
		(start 29.899864 -295.491662)
		(end 31.972758 -295.491662)
		(width 0.1016)
		(layer "F.Cu")
		(net "M_C_CPU1_SA_DQ<19>")
	)
	(segment
		(start 31.972758 -295.491662)
		(end 32.51708 -295.491662)
		(width 0.20066)
		(layer "F.Cu")
		(net "M_C_CPU1_SA_DQ<19>")
	)
	(segment
		(start 33.848294 -295.274238)
		(end 34.055812 -295.06672)
		(width 0.20066)
		(layer "F.Cu")
		(net "M_C_CPU1_SA_DQ<19>")
	)
	(segment
		(start 32.666178 -295.190926)
		(end 32.794702 -295.062402)
		(width 0.20066)
		(layer "F.Cu")
		(net "M_C_CPU1_SA_DQ<19>")
	)
	(segment
		(start 93.894148 -268.034008)
		(end 93.894148 -268.569694)
		(width 0.20066)
		(layer "F.Cu")
		(net "M_C_CPU1_SA_DQ<19>")
	)
	(segment
		(start 32.51708 -295.491662)
		(end 32.666178 -295.342564)
		(width 0.20066)
		(layer "F.Cu")
		(net "M_C_CPU1_SA_DQ<19>")
	)
	(segment
		(start 29.647642 -295.505886)
		(end 29.661866 -295.491662)
		(width 0.101854)
		(layer "F.Cu")
		(net "M_C_CPU1_SA_DQ<19>")
	)
	(segment
		(start 34.055812 -295.06672)
		(end 34.871914 -295.06672)
		(width 0.20066)
		(layer "F.Cu")
		(net "M_C_CPU1_SA_DQ<19>")
	)
	(segment
		(start 29.29382 -295.505886)
		(end 29.647642 -295.505886)
		(width 0.20066)
		(layer "F.Cu")
		(net "M_C_CPU1_SA_DQ<19>")
	)
	(segment
		(start 35.976814 -295.06672)
		(end 34.871914 -295.06672)
		(width 0.20066)
		(layer "F.Cu")
		(net "M_C_CPU1_SA_DQ<19>")
	)
	(segment
		(start 27.328114 -295.06672)
		(end 29.025342 -295.06672)
		(width 0.20066)
		(layer "F.Cu")
		(net "M_C_CPU1_SA_DQ<19>")
	)
	(segment
		(start 33.401762 -295.274238)
		(end 33.848294 -295.274238)
		(width 0.20066)
		(layer "F.Cu")
		(net "M_C_CPU1_SA_DQ<19>")
	)
	(segment
		(start 29.151326 -295.192704)
		(end 29.151326 -295.363392)
		(width 0.20066)
		(layer "F.Cu")
		(net "M_C_CPU1_SA_DQ<19>")
	)
	(segment
		(start 29.151326 -295.363392)
		(end 29.29382 -295.505886)
		(width 0.20066)
		(layer "F.Cu")
		(net "M_C_CPU1_SA_DQ<19>")
	)
	(segment
		(start 32.794702 -295.062402)
		(end 33.189926 -295.062402)
		(width 0.20066)
		(layer "F.Cu")
		(net "M_C_CPU1_SA_DQ<19>")
	)
	(segment
		(start 29.025342 -295.06672)
		(end 29.151326 -295.192704)
		(width 0.20066)
		(layer "F.Cu")
		(net "M_C_CPU1_SA_DQ<19>")
	)
	(segment
		(start 93.893894 -268.033754)
		(end 93.894148 -268.034008)
		(width 0.20066)
		(layer "F.Cu")
		(net "M_C_CPU1_SA_DQ<19>")
	)
	(segment
		(start 33.189926 -295.062402)
		(end 33.401762 -295.274238)
		(width 0.20066)
		(layer "F.Cu")
		(net "M_C_CPU1_SA_DQ<19>")
	)
	(segment
		(start 59.73826 -293.076122)
		(end 58.667904 -293.076122)
		(width 0.18288)
		(layer "In4.Cu")
		(net "M_C_CPU1_SA_DQ<19>")
	)
	(segment
		(start 64.692276 -290.147756)
		(end 64.692276 -290.35502)
		(width 0.18288)
		(layer "In4.Cu")
		(net "M_C_CPU1_SA_DQ<19>")
	)
	(segment
		(start 38.581584 -295.120568)
		(end 38.398704 -294.937688)
		(width 0.18288)
		(layer "In4.Cu")
		(net "M_C_CPU1_SA_DQ<19>")
	)
	(segment
		(start 63.143384 -290.51504)
		(end 62.347094 -291.31133)
		(width 0.18288)
		(layer "In4.Cu")
		(net "M_C_CPU1_SA_DQ<19>")
	)
	(segment
		(start 42.698416 -295.275)
		(end 42.698416 -294.859964)
		(width 0.18288)
		(layer "In4.Cu")
		(net "M_C_CPU1_SA_DQ<19>")
	)
	(segment
		(start 37.890704 -295.44645)
		(end 37.707824 -295.62933)
		(width 0.18288)
		(layer "In4.Cu")
		(net "M_C_CPU1_SA_DQ<19>")
	)
	(segment
		(start 90.887296 -268.894052)
		(end 90.881454 -268.89075)
		(width 0.088646)
		(layer "In4.Cu")
		(net "M_C_CPU1_SA_DQ<19>")
	)
	(segment
		(start 42.698416 -294.859964)
		(end 42.515536 -294.677084)
		(width 0.18288)
		(layer "In4.Cu")
		(net "M_C_CPU1_SA_DQ<19>")
	)
	(segment
		(start 37.890704 -295.120568)
		(end 37.890704 -295.44645)
		(width 0.18288)
		(layer "In4.Cu")
		(net "M_C_CPU1_SA_DQ<19>")
	)
	(segment
		(start 38.764464 -295.62933)
		(end 38.581584 -295.44645)
		(width 0.18288)
		(layer "In4.Cu")
		(net "M_C_CPU1_SA_DQ<19>")
	)
	(segment
		(start 64.852296 -289.987736)
		(end 64.692276 -290.147756)
		(width 0.18288)
		(layer "In4.Cu")
		(net "M_C_CPU1_SA_DQ<19>")
	)
	(segment
		(start 36.539424 -295.62933)
		(end 35.976814 -295.06672)
		(width 0.18288)
		(layer "In4.Cu")
		(net "M_C_CPU1_SA_DQ<19>")
	)
	(segment
		(start 66.728086 -289.434524)
		(end 65.753488 -289.434524)
		(width 0.18288)
		(layer "In4.Cu")
		(net "M_C_CPU1_SA_DQ<19>")
	)
	(segment
		(start 60.420758 -292.19271)
		(end 60.420758 -292.57879)
		(width 0.18288)
		(layer "In4.Cu")
		(net "M_C_CPU1_SA_DQ<19>")
	)
	(segment
		(start 41.316656 -295.275)
		(end 41.316656 -294.859964)
		(width 0.18288)
		(layer "In4.Cu")
		(net "M_C_CPU1_SA_DQ<19>")
	)
	(segment
		(start 37.707824 -295.62933)
		(end 36.539424 -295.62933)
		(width 0.18288)
		(layer "In4.Cu")
		(net "M_C_CPU1_SA_DQ<19>")
	)
	(segment
		(start 65.753488 -289.434524)
		(end 65.200276 -289.987736)
		(width 0.18288)
		(layer "In4.Cu")
		(net "M_C_CPU1_SA_DQ<19>")
	)
	(segment
		(start 65.200276 -289.987736)
		(end 64.852296 -289.987736)
		(width 0.18288)
		(layer "In4.Cu")
		(net "M_C_CPU1_SA_DQ<19>")
	)
	(segment
		(start 41.499536 -295.45788)
		(end 41.316656 -295.275)
		(width 0.18288)
		(layer "In4.Cu")
		(net "M_C_CPU1_SA_DQ<19>")
	)
	(segment
		(start 41.824656 -295.45788)
		(end 41.499536 -295.45788)
		(width 0.18288)
		(layer "In4.Cu")
		(net "M_C_CPU1_SA_DQ<19>")
	)
	(segment
		(start 69.75983 -286.40278)
		(end 66.728086 -289.434524)
		(width 0.18288)
		(layer "In4.Cu")
		(net "M_C_CPU1_SA_DQ<19>")
	)
	(segment
		(start 47.556928 -296.343578)
		(end 44.957746 -296.343578)
		(width 0.18288)
		(layer "In4.Cu")
		(net "M_C_CPU1_SA_DQ<19>")
	)
	(segment
		(start 52.347368 -295.489376)
		(end 48.41113 -295.489376)
		(width 0.18288)
		(layer "In4.Cu")
		(net "M_C_CPU1_SA_DQ<19>")
	)
	(segment
		(start 64.692276 -290.35502)
		(end 64.532256 -290.51504)
		(width 0.18288)
		(layer "In4.Cu")
		(net "M_C_CPU1_SA_DQ<19>")
	)
	(segment
		(start 89.007696 -268.894052)
		(end 89.001854 -268.89075)
		(width 0.088646)
		(layer "In4.Cu")
		(net "M_C_CPU1_SA_DQ<19>")
	)
	(segment
		(start 89.011506 -268.896338)
		(end 89.007696 -268.894052)
		(width 0.088646)
		(layer "In4.Cu")
		(net "M_C_CPU1_SA_DQ<19>")
	)
	(segment
		(start 39.674038 -295.62933)
		(end 38.764464 -295.62933)
		(width 0.18288)
		(layer "In4.Cu")
		(net "M_C_CPU1_SA_DQ<19>")
	)
	(segment
		(start 44.957746 -296.343578)
		(end 44.072048 -295.45788)
		(width 0.18288)
		(layer "In4.Cu")
		(net "M_C_CPU1_SA_DQ<19>")
	)
	(segment
		(start 42.190416 -294.677084)
		(end 42.007536 -294.859964)
		(width 0.18288)
		(layer "In4.Cu")
		(net "M_C_CPU1_SA_DQ<19>")
	)
	(segment
		(start 90.893138 -268.897608)
		(end 90.887296 -268.894052)
		(width 0.088646)
		(layer "In4.Cu")
		(net "M_C_CPU1_SA_DQ<19>")
	)
	(segment
		(start 58.667904 -293.076122)
		(end 56.944768 -293.789862)
		(width 0.18288)
		(layer "In4.Cu")
		(net "M_C_CPU1_SA_DQ<19>")
	)
	(segment
		(start 84.372958 -269.260574)
		(end 83.509612 -270.12392)
		(width 0.088646)
		(layer "In4.Cu")
		(net "M_C_CPU1_SA_DQ<19>")
	)
	(segment
		(start 82.7151 -270.12392)
		(end 72.110092 -280.728928)
		(width 0.18288)
		(layer "In4.Cu")
		(net "M_C_CPU1_SA_DQ<19>")
	)
	(segment
		(start 41.133776 -294.677084)
		(end 40.808656 -294.677084)
		(width 0.18288)
		(layer "In4.Cu")
		(net "M_C_CPU1_SA_DQ<19>")
	)
	(segment
		(start 54.046882 -293.789862)
		(end 52.347368 -295.489376)
		(width 0.18288)
		(layer "In4.Cu")
		(net "M_C_CPU1_SA_DQ<19>")
	)
	(segment
		(start 38.581584 -295.44645)
		(end 38.581584 -295.120568)
		(width 0.18288)
		(layer "In4.Cu")
		(net "M_C_CPU1_SA_DQ<19>")
	)
	(segment
		(start 39.845488 -295.45788)
		(end 39.674038 -295.62933)
		(width 0.18288)
		(layer "In4.Cu")
		(net "M_C_CPU1_SA_DQ<19>")
	)
	(segment
		(start 93.156278 -268.253972)
		(end 93.141546 -268.245336)
		(width 0.088646)
		(layer "In4.Cu")
		(net "M_C_CPU1_SA_DQ<19>")
	)
	(segment
		(start 42.007536 -294.859964)
		(end 42.007536 -295.275)
		(width 0.18288)
		(layer "In4.Cu")
		(net "M_C_CPU1_SA_DQ<19>")
	)
	(segment
		(start 89.951814 -268.896592)
		(end 89.947496 -268.894052)
		(width 0.088646)
		(layer "In4.Cu")
		(net "M_C_CPU1_SA_DQ<19>")
	)
	(segment
		(start 72.110092 -280.728928)
		(end 69.75983 -286.40278)
		(width 0.18288)
		(layer "In4.Cu")
		(net "M_C_CPU1_SA_DQ<19>")
	)
	(segment
		(start 60.420758 -292.57879)
		(end 60.054236 -292.945312)
		(width 0.18288)
		(layer "In4.Cu")
		(net "M_C_CPU1_SA_DQ<19>")
	)
	(segment
		(start 40.625776 -294.859964)
		(end 40.625776 -295.275)
		(width 0.18288)
		(layer "In4.Cu")
		(net "M_C_CPU1_SA_DQ<19>")
	)
	(segment
		(start 38.073584 -294.937688)
		(end 37.890704 -295.120568)
		(width 0.18288)
		(layer "In4.Cu")
		(net "M_C_CPU1_SA_DQ<19>")
	)
	(segment
		(start 56.944768 -293.789862)
		(end 54.046882 -293.789862)
		(width 0.18288)
		(layer "In4.Cu")
		(net "M_C_CPU1_SA_DQ<19>")
	)
	(segment
		(start 88.072214 -268.896592)
		(end 88.067896 -268.894052)
		(width 0.088646)
		(layer "In4.Cu")
		(net "M_C_CPU1_SA_DQ<19>")
	)
	(segment
		(start 83.318604 -270.12392)
		(end 82.7151 -270.12392)
		(width 0.18288)
		(layer "In4.Cu")
		(net "M_C_CPU1_SA_DQ<19>")
	)
	(segment
		(start 42.515536 -294.677084)
		(end 42.190416 -294.677084)
		(width 0.18288)
		(layer "In4.Cu")
		(net "M_C_CPU1_SA_DQ<19>")
	)
	(segment
		(start 91.73083 -268.31798)
		(end 91.677236 -268.371574)
		(width 0.088646)
		(layer "In4.Cu")
		(net "M_C_CPU1_SA_DQ<19>")
	)
	(segment
		(start 64.532256 -290.51504)
		(end 63.143384 -290.51504)
		(width 0.18288)
		(layer "In4.Cu")
		(net "M_C_CPU1_SA_DQ<19>")
	)
	(segment
		(start 48.41113 -295.489376)
		(end 47.556928 -296.343578)
		(width 0.18288)
		(layer "In4.Cu")
		(net "M_C_CPU1_SA_DQ<19>")
	)
	(segment
		(start 40.625776 -295.275)
		(end 40.442896 -295.45788)
		(width 0.18288)
		(layer "In4.Cu")
		(net "M_C_CPU1_SA_DQ<19>")
	)
	(segment
		(start 83.509612 -270.12392)
		(end 83.318604 -270.12392)
		(width 0.088646)
		(layer "In4.Cu")
		(net "M_C_CPU1_SA_DQ<19>")
	)
	(segment
		(start 40.808656 -294.677084)
		(end 40.625776 -294.859964)
		(width 0.18288)
		(layer "In4.Cu")
		(net "M_C_CPU1_SA_DQ<19>")
	)
	(segment
		(start 42.007536 -295.275)
		(end 41.824656 -295.45788)
		(width 0.18288)
		(layer "In4.Cu")
		(net "M_C_CPU1_SA_DQ<19>")
	)
	(segment
		(start 62.347094 -291.31133)
		(end 61.302138 -291.31133)
		(width 0.18288)
		(layer "In4.Cu")
		(net "M_C_CPU1_SA_DQ<19>")
	)
	(segment
		(start 41.316656 -294.859964)
		(end 41.133776 -294.677084)
		(width 0.18288)
		(layer "In4.Cu")
		(net "M_C_CPU1_SA_DQ<19>")
	)
	(segment
		(start 44.072048 -295.45788)
		(end 42.881296 -295.45788)
		(width 0.18288)
		(layer "In4.Cu")
		(net "M_C_CPU1_SA_DQ<19>")
	)
	(segment
		(start 40.442896 -295.45788)
		(end 39.845488 -295.45788)
		(width 0.18288)
		(layer "In4.Cu")
		(net "M_C_CPU1_SA_DQ<19>")
	)
	(segment
		(start 61.302138 -291.31133)
		(end 60.420758 -292.19271)
		(width 0.18288)
		(layer "In4.Cu")
		(net "M_C_CPU1_SA_DQ<19>")
	)
	(segment
		(start 91.832938 -268.242034)
		(end 91.821254 -268.248638)
		(width 0.088646)
		(layer "In4.Cu")
		(net "M_C_CPU1_SA_DQ<19>")
	)
	(segment
		(start 38.398704 -294.937688)
		(end 38.073584 -294.937688)
		(width 0.18288)
		(layer "In4.Cu")
		(net "M_C_CPU1_SA_DQ<19>")
	)
	(segment
		(start 42.881296 -295.45788)
		(end 42.698416 -295.275)
		(width 0.18288)
		(layer "In4.Cu")
		(net "M_C_CPU1_SA_DQ<19>")
	)
	(segment
		(start 60.054236 -292.945312)
		(end 59.73826 -293.076122)
		(width 0.18288)
		(layer "In4.Cu")
		(net "M_C_CPU1_SA_DQ<19>")
	)
	(arc
		(start 92.76715 -268.245336)
		(mid 92.484448 -268.321078)
		(end 92.201746 -268.245336)
		(width 0.088646)
		(layer "In4.Cu")
		(net "M_C_CPU1_SA_DQ<19>")
	)
	(arc
		(start 91.261946 -268.894052)
		(mid 91.078022 -268.944306)
		(end 90.893138 -268.897608)
		(width 0.088646)
		(layer "In4.Cu")
		(net "M_C_CPU1_SA_DQ<19>")
	)
	(arc
		(start 91.536774 -268.581124)
		(mid 91.425083 -268.760179)
		(end 91.261946 -268.894052)
		(width 0.088646)
		(layer "In4.Cu")
		(net "M_C_CPU1_SA_DQ<19>")
	)
	(arc
		(start 86.562692 -268.894052)
		(mid 86.375494 -268.944195)
		(end 86.188296 -268.894052)
		(width 0.088646)
		(layer "In4.Cu")
		(net "M_C_CPU1_SA_DQ<19>")
	)
	(arc
		(start 90.322146 -268.894052)
		(mid 90.137309 -268.944313)
		(end 89.951814 -268.896592)
		(width 0.088646)
		(layer "In4.Cu")
		(net "M_C_CPU1_SA_DQ<19>")
	)
	(arc
		(start 86.188296 -268.894052)
		(mid 85.905594 -268.818276)
		(end 85.622892 -268.894052)
		(width 0.088646)
		(layer "In4.Cu")
		(net "M_C_CPU1_SA_DQ<19>")
	)
	(arc
		(start 92.201746 -268.245336)
		(mid 92.017792 -268.195207)
		(end 91.832938 -268.242034)
		(width 0.088646)
		(layer "In4.Cu")
		(net "M_C_CPU1_SA_DQ<19>")
	)
	(arc
		(start 93.141546 -268.245336)
		(mid 92.954348 -268.195193)
		(end 92.76715 -268.245336)
		(width 0.088646)
		(layer "In4.Cu")
		(net "M_C_CPU1_SA_DQ<19>")
	)
	(arc
		(start 84.581238 -269.174214)
		(mid 84.468498 -269.196657)
		(end 84.372958 -269.260574)
		(width 0.088646)
		(layer "In4.Cu")
		(net "M_C_CPU1_SA_DQ<19>")
	)
	(arc
		(start 89.001854 -268.89075)
		(mid 88.721749 -268.818308)
		(end 88.442546 -268.894052)
		(width 0.088646)
		(layer "In4.Cu")
		(net "M_C_CPU1_SA_DQ<19>")
	)
	(arc
		(start 88.067896 -268.894052)
		(mid 87.785194 -268.818276)
		(end 87.502492 -268.894052)
		(width 0.088646)
		(layer "In4.Cu")
		(net "M_C_CPU1_SA_DQ<19>")
	)
	(arc
		(start 88.442546 -268.894052)
		(mid 88.257709 -268.944313)
		(end 88.072214 -268.896592)
		(width 0.088646)
		(layer "In4.Cu")
		(net "M_C_CPU1_SA_DQ<19>")
	)
	(arc
		(start 87.502492 -268.894052)
		(mid 87.315294 -268.944195)
		(end 87.128096 -268.894052)
		(width 0.088646)
		(layer "In4.Cu")
		(net "M_C_CPU1_SA_DQ<19>")
	)
	(arc
		(start 87.128096 -268.894052)
		(mid 86.845394 -268.818276)
		(end 86.562692 -268.894052)
		(width 0.088646)
		(layer "In4.Cu")
		(net "M_C_CPU1_SA_DQ<19>")
	)
	(arc
		(start 90.881454 -268.89075)
		(mid 90.601349 -268.818308)
		(end 90.322146 -268.894052)
		(width 0.088646)
		(layer "In4.Cu")
		(net "M_C_CPU1_SA_DQ<19>")
	)
	(arc
		(start 91.677236 -268.371574)
		(mid 91.596744 -268.469472)
		(end 91.536774 -268.581124)
		(width 0.088646)
		(layer "In4.Cu")
		(net "M_C_CPU1_SA_DQ<19>")
	)
	(arc
		(start 89.947496 -268.894052)
		(mid 89.664938 -268.818403)
		(end 89.382346 -268.894052)
		(width 0.088646)
		(layer "In4.Cu")
		(net "M_C_CPU1_SA_DQ<19>")
	)
	(arc
		(start 85.622892 -268.894052)
		(mid 85.120567 -269.102909)
		(end 84.581238 -269.174214)
		(width 0.088646)
		(layer "In4.Cu")
		(net "M_C_CPU1_SA_DQ<19>")
	)
	(arc
		(start 93.894148 -268.569694)
		(mid 93.515267 -268.43508)
		(end 93.156278 -268.253972)
		(width 0.088646)
		(layer "In4.Cu")
		(net "M_C_CPU1_SA_DQ<19>")
	)
	(arc
		(start 91.821254 -268.248638)
		(mid 91.773762 -268.280336)
		(end 91.73083 -268.31798)
		(width 0.088646)
		(layer "In4.Cu")
		(net "M_C_CPU1_SA_DQ<19>")
	)
	(arc
		(start 89.382346 -268.894052)
		(mid 89.197225 -268.944315)
		(end 89.011506 -268.896338)
		(width 0.088646)
		(layer "In4.Cu")
		(net "M_C_CPU1_SA_DQ<19>")
	)
	(segment
		(start 35.976814 -296.766742)
		(end 34.871914 -296.766742)
		(width 0.20066)
		(layer "F.Cu")
		(net "M_C_CPU1_SA_DQ<18>")
	)
	(segment
		(start 93.423994 -268.847824)
		(end 93.423994 -269.38351)
		(width 0.20066)
		(layer "F.Cu")
		(net "M_C_CPU1_SA_DQ<18>")
	)
	(segment
		(start 32.916876 -296.978578)
		(end 33.345374 -296.978578)
		(width 0.20066)
		(layer "F.Cu")
		(net "M_C_CPU1_SA_DQ<18>")
	)
	(segment
		(start 32.605726 -296.3418)
		(end 32.74949 -296.485564)
		(width 0.20066)
		(layer "F.Cu")
		(net "M_C_CPU1_SA_DQ<18>")
	)
	(segment
		(start 33.55721 -296.766742)
		(end 34.871914 -296.766742)
		(width 0.20066)
		(layer "F.Cu")
		(net "M_C_CPU1_SA_DQ<18>")
	)
	(segment
		(start 93.424248 -268.84757)
		(end 93.423994 -268.847824)
		(width 0.20066)
		(layer "F.Cu")
		(net "M_C_CPU1_SA_DQ<18>")
	)
	(segment
		(start 32.74949 -296.811192)
		(end 32.916876 -296.978578)
		(width 0.20066)
		(layer "F.Cu")
		(net "M_C_CPU1_SA_DQ<18>")
	)
	(segment
		(start 28.91028 -296.33164)
		(end 29.647642 -296.33164)
		(width 0.20066)
		(layer "F.Cu")
		(net "M_C_CPU1_SA_DQ<18>")
	)
	(segment
		(start 32.74949 -296.485564)
		(end 32.74949 -296.811192)
		(width 0.20066)
		(layer "F.Cu")
		(net "M_C_CPU1_SA_DQ<18>")
	)
	(segment
		(start 29.647642 -296.33164)
		(end 29.657802 -296.3418)
		(width 0.101854)
		(layer "F.Cu")
		(net "M_C_CPU1_SA_DQ<18>")
	)
	(segment
		(start 29.657802 -296.3418)
		(end 29.912818 -296.3418)
		(width 0.101854)
		(layer "F.Cu")
		(net "M_C_CPU1_SA_DQ<18>")
	)
	(segment
		(start 27.328114 -296.766742)
		(end 28.475178 -296.766742)
		(width 0.20066)
		(layer "F.Cu")
		(net "M_C_CPU1_SA_DQ<18>")
	)
	(segment
		(start 31.972758 -296.3418)
		(end 32.605726 -296.3418)
		(width 0.20066)
		(layer "F.Cu")
		(net "M_C_CPU1_SA_DQ<18>")
	)
	(segment
		(start 33.345374 -296.978578)
		(end 33.55721 -296.766742)
		(width 0.20066)
		(layer "F.Cu")
		(net "M_C_CPU1_SA_DQ<18>")
	)
	(segment
		(start 29.912818 -296.3418)
		(end 31.972758 -296.3418)
		(width 0.1016)
		(layer "F.Cu")
		(net "M_C_CPU1_SA_DQ<18>")
	)
	(segment
		(start 28.475178 -296.766742)
		(end 28.91028 -296.33164)
		(width 0.20066)
		(layer "F.Cu")
		(net "M_C_CPU1_SA_DQ<18>")
	)
	(segment
		(start 46.153832 -297.844464)
		(end 45.970952 -298.027344)
		(width 0.18288)
		(layer "In4.Cu")
		(net "M_C_CPU1_SA_DQ<18>")
	)
	(segment
		(start 60.507626 -293.947342)
		(end 60.13196 -294.10279)
		(width 0.18288)
		(layer "In4.Cu")
		(net "M_C_CPU1_SA_DQ<18>")
	)
	(segment
		(start 73.017888 -281.229562)
		(end 70.46214 -287.399222)
		(width 0.18288)
		(layer "In4.Cu")
		(net "M_C_CPU1_SA_DQ<18>")
	)
	(segment
		(start 50.153824 -297.742356)
		(end 49.970944 -297.925236)
		(width 0.18288)
		(layer "In4.Cu")
		(net "M_C_CPU1_SA_DQ<18>")
	)
	(segment
		(start 59.60745 -294.10279)
		(end 59.218068 -294.26408)
		(width 0.18288)
		(layer "In4.Cu")
		(net "M_C_CPU1_SA_DQ<18>")
	)
	(segment
		(start 46.476666 -297.844464)
		(end 46.153832 -297.844464)
		(width 0.18288)
		(layer "In4.Cu")
		(net "M_C_CPU1_SA_DQ<18>")
	)
	(segment
		(start 84.412836 -269.79626)
		(end 84.412836 -270.296132)
		(width 0.088646)
		(layer "In4.Cu")
		(net "M_C_CPU1_SA_DQ<18>")
	)
	(segment
		(start 56.869076 -295.492932)
		(end 54.25694 -295.492932)
		(width 0.18288)
		(layer "In4.Cu")
		(net "M_C_CPU1_SA_DQ<18>")
	)
	(segment
		(start 44.2722 -297.703494)
		(end 43.550332 -296.981626)
		(width 0.18288)
		(layer "In4.Cu")
		(net "M_C_CPU1_SA_DQ<18>")
	)
	(segment
		(start 49.280064 -297.189144)
		(end 48.46193 -297.189144)
		(width 0.18288)
		(layer "In4.Cu")
		(net "M_C_CPU1_SA_DQ<18>")
	)
	(segment
		(start 46.673516 -298.041314)
		(end 46.476666 -297.844464)
		(width 0.18288)
		(layer "In4.Cu")
		(net "M_C_CPU1_SA_DQ<18>")
	)
	(segment
		(start 40.506904 -296.981626)
		(end 40.166544 -297.321986)
		(width 0.18288)
		(layer "In4.Cu")
		(net "M_C_CPU1_SA_DQ<18>")
	)
	(segment
		(start 52.560728 -297.189144)
		(end 50.336704 -297.189144)
		(width 0.18288)
		(layer "In4.Cu")
		(net "M_C_CPU1_SA_DQ<18>")
	)
	(segment
		(start 59.218068 -294.26408)
		(end 58.90133 -294.580818)
		(width 0.18288)
		(layer "In4.Cu")
		(net "M_C_CPU1_SA_DQ<18>")
	)
	(segment
		(start 83.318604 -271.1196)
		(end 83.12785 -271.1196)
		(width 0.18288)
		(layer "In4.Cu")
		(net "M_C_CPU1_SA_DQ<18>")
	)
	(segment
		(start 92.201746 -268.894052)
		(end 92.19565 -268.897608)
		(width 0.088646)
		(layer "In4.Cu")
		(net "M_C_CPU1_SA_DQ<18>")
	)
	(segment
		(start 43.550332 -296.981626)
		(end 40.506904 -296.981626)
		(width 0.18288)
		(layer "In4.Cu")
		(net "M_C_CPU1_SA_DQ<18>")
	)
	(segment
		(start 36.430712 -297.22064)
		(end 35.976814 -296.766742)
		(width 0.18288)
		(layer "In4.Cu")
		(net "M_C_CPU1_SA_DQ<18>")
	)
	(segment
		(start 49.970944 -297.925236)
		(end 49.645824 -297.925236)
		(width 0.18288)
		(layer "In4.Cu")
		(net "M_C_CPU1_SA_DQ<18>")
	)
	(segment
		(start 49.462944 -297.372024)
		(end 49.280064 -297.189144)
		(width 0.18288)
		(layer "In4.Cu")
		(net "M_C_CPU1_SA_DQ<18>")
	)
	(segment
		(start 65.010792 -292.133528)
		(end 63.213488 -292.133528)
		(width 0.18288)
		(layer "In4.Cu")
		(net "M_C_CPU1_SA_DQ<18>")
	)
	(segment
		(start 62.558676 -292.78834)
		(end 61.0362 -293.418768)
		(width 0.18288)
		(layer "In4.Cu")
		(net "M_C_CPU1_SA_DQ<18>")
	)
	(segment
		(start 38.955472 -297.007026)
		(end 38.431724 -297.007026)
		(width 0.18288)
		(layer "In4.Cu")
		(net "M_C_CPU1_SA_DQ<18>")
	)
	(segment
		(start 39.270432 -297.321986)
		(end 38.955472 -297.007026)
		(width 0.18288)
		(layer "In4.Cu")
		(net "M_C_CPU1_SA_DQ<18>")
	)
	(segment
		(start 84.635848 -269.573248)
		(end 84.412836 -269.79626)
		(width 0.088646)
		(layer "In4.Cu")
		(net "M_C_CPU1_SA_DQ<18>")
	)
	(segment
		(start 38.21811 -297.22064)
		(end 36.430712 -297.22064)
		(width 0.18288)
		(layer "In4.Cu")
		(net "M_C_CPU1_SA_DQ<18>")
	)
	(segment
		(start 66.111628 -291.032692)
		(end 65.010792 -292.133528)
		(width 0.18288)
		(layer "In4.Cu")
		(net "M_C_CPU1_SA_DQ<18>")
	)
	(segment
		(start 66.82867 -291.032692)
		(end 66.111628 -291.032692)
		(width 0.18288)
		(layer "In4.Cu")
		(net "M_C_CPU1_SA_DQ<18>")
	)
	(segment
		(start 92.216478 -268.885416)
		(end 92.201746 -268.894052)
		(width 0.088646)
		(layer "In4.Cu")
		(net "M_C_CPU1_SA_DQ<18>")
	)
	(segment
		(start 70.46214 -287.399222)
		(end 66.82867 -291.032692)
		(width 0.18288)
		(layer "In4.Cu")
		(net "M_C_CPU1_SA_DQ<18>")
	)
	(segment
		(start 45.280072 -297.886374)
		(end 45.097192 -297.703494)
		(width 0.18288)
		(layer "In4.Cu")
		(net "M_C_CPU1_SA_DQ<18>")
	)
	(segment
		(start 84.412836 -270.296132)
		(end 83.589368 -271.1196)
		(width 0.088646)
		(layer "In4.Cu")
		(net "M_C_CPU1_SA_DQ<18>")
	)
	(segment
		(start 47.60976 -298.041314)
		(end 46.673516 -298.041314)
		(width 0.18288)
		(layer "In4.Cu")
		(net "M_C_CPU1_SA_DQ<18>")
	)
	(segment
		(start 58.552842 -294.72509)
		(end 57.636918 -294.72509)
		(width 0.18288)
		(layer "In4.Cu")
		(net "M_C_CPU1_SA_DQ<18>")
	)
	(segment
		(start 54.25694 -295.492932)
		(end 52.560728 -297.189144)
		(width 0.18288)
		(layer "In4.Cu")
		(net "M_C_CPU1_SA_DQ<18>")
	)
	(segment
		(start 45.970952 -298.027344)
		(end 45.970952 -298.19346)
		(width 0.18288)
		(layer "In4.Cu")
		(net "M_C_CPU1_SA_DQ<18>")
	)
	(segment
		(start 91.919044 -269.38351)
		(end 91.919044 -269.392146)
		(width 0.088646)
		(layer "In4.Cu")
		(net "M_C_CPU1_SA_DQ<18>")
	)
	(segment
		(start 49.462944 -297.742356)
		(end 49.462944 -297.372024)
		(width 0.18288)
		(layer "In4.Cu")
		(net "M_C_CPU1_SA_DQ<18>")
	)
	(segment
		(start 93.11132 -269.38351)
		(end 93.045788 -269.317978)
		(width 0.088646)
		(layer "In4.Cu")
		(net "M_C_CPU1_SA_DQ<18>")
	)
	(segment
		(start 48.46193 -297.189144)
		(end 47.60976 -298.041314)
		(width 0.18288)
		(layer "In4.Cu")
		(net "M_C_CPU1_SA_DQ<18>")
	)
	(segment
		(start 45.970952 -298.19346)
		(end 45.788072 -298.37634)
		(width 0.18288)
		(layer "In4.Cu")
		(net "M_C_CPU1_SA_DQ<18>")
	)
	(segment
		(start 45.788072 -298.37634)
		(end 45.462952 -298.37634)
		(width 0.18288)
		(layer "In4.Cu")
		(net "M_C_CPU1_SA_DQ<18>")
	)
	(segment
		(start 85.56498 -269.573248)
		(end 84.635848 -269.573248)
		(width 0.088646)
		(layer "In4.Cu")
		(net "M_C_CPU1_SA_DQ<18>")
	)
	(segment
		(start 58.90133 -294.580818)
		(end 58.552842 -294.72509)
		(width 0.18288)
		(layer "In4.Cu")
		(net "M_C_CPU1_SA_DQ<18>")
	)
	(segment
		(start 40.166544 -297.321986)
		(end 39.270432 -297.321986)
		(width 0.18288)
		(layer "In4.Cu")
		(net "M_C_CPU1_SA_DQ<18>")
	)
	(segment
		(start 60.13196 -294.10279)
		(end 59.60745 -294.10279)
		(width 0.18288)
		(layer "In4.Cu")
		(net "M_C_CPU1_SA_DQ<18>")
	)
	(segment
		(start 50.336704 -297.189144)
		(end 50.153824 -297.372024)
		(width 0.18288)
		(layer "In4.Cu")
		(net "M_C_CPU1_SA_DQ<18>")
	)
	(segment
		(start 61.0362 -293.418768)
		(end 60.507626 -293.947342)
		(width 0.18288)
		(layer "In4.Cu")
		(net "M_C_CPU1_SA_DQ<18>")
	)
	(segment
		(start 38.431724 -297.007026)
		(end 38.21811 -297.22064)
		(width 0.18288)
		(layer "In4.Cu")
		(net "M_C_CPU1_SA_DQ<18>")
	)
	(segment
		(start 83.12785 -271.1196)
		(end 73.017888 -281.229562)
		(width 0.18288)
		(layer "In4.Cu")
		(net "M_C_CPU1_SA_DQ<18>")
	)
	(segment
		(start 85.640418 -269.648686)
		(end 85.56498 -269.573248)
		(width 0.088646)
		(layer "In4.Cu")
		(net "M_C_CPU1_SA_DQ<18>")
	)
	(segment
		(start 45.462952 -298.37634)
		(end 45.280072 -298.19346)
		(width 0.18288)
		(layer "In4.Cu")
		(net "M_C_CPU1_SA_DQ<18>")
	)
	(segment
		(start 91.35745 -269.707868)
		(end 91.347036 -269.701772)
		(width 0.088646)
		(layer "In4.Cu")
		(net "M_C_CPU1_SA_DQ<18>")
	)
	(segment
		(start 57.636918 -294.72509)
		(end 56.869076 -295.492932)
		(width 0.18288)
		(layer "In4.Cu")
		(net "M_C_CPU1_SA_DQ<18>")
	)
	(segment
		(start 49.645824 -297.925236)
		(end 49.462944 -297.742356)
		(width 0.18288)
		(layer "In4.Cu")
		(net "M_C_CPU1_SA_DQ<18>")
	)
	(segment
		(start 63.213488 -292.133528)
		(end 62.558676 -292.78834)
		(width 0.18288)
		(layer "In4.Cu")
		(net "M_C_CPU1_SA_DQ<18>")
	)
	(segment
		(start 50.153824 -297.372024)
		(end 50.153824 -297.742356)
		(width 0.18288)
		(layer "In4.Cu")
		(net "M_C_CPU1_SA_DQ<18>")
	)
	(segment
		(start 83.589368 -271.1196)
		(end 83.318604 -271.1196)
		(width 0.088646)
		(layer "In4.Cu")
		(net "M_C_CPU1_SA_DQ<18>")
	)
	(segment
		(start 45.280072 -298.19346)
		(end 45.280072 -297.886374)
		(width 0.18288)
		(layer "In4.Cu")
		(net "M_C_CPU1_SA_DQ<18>")
	)
	(segment
		(start 45.097192 -297.703494)
		(end 44.2722 -297.703494)
		(width 0.18288)
		(layer "In4.Cu")
		(net "M_C_CPU1_SA_DQ<18>")
	)
	(segment
		(start 93.423994 -269.38351)
		(end 93.11132 -269.38351)
		(width 0.088646)
		(layer "In4.Cu")
		(net "M_C_CPU1_SA_DQ<18>")
	)
	(arc
		(start 88.912192 -269.707868)
		(mid 88.724994 -269.758011)
		(end 88.537796 -269.707868)
		(width 0.088646)
		(layer "In4.Cu")
		(net "M_C_CPU1_SA_DQ<18>")
	)
	(arc
		(start 89.477596 -269.707868)
		(mid 89.194894 -269.632126)
		(end 88.912192 -269.707868)
		(width 0.088646)
		(layer "In4.Cu")
		(net "M_C_CPU1_SA_DQ<18>")
	)
	(arc
		(start 86.092792 -269.707868)
		(mid 85.905594 -269.758011)
		(end 85.718396 -269.707868)
		(width 0.088646)
		(layer "In4.Cu")
		(net "M_C_CPU1_SA_DQ<18>")
	)
	(arc
		(start 88.537796 -269.707868)
		(mid 88.255094 -269.632126)
		(end 87.972392 -269.707868)
		(width 0.088646)
		(layer "In4.Cu")
		(net "M_C_CPU1_SA_DQ<18>")
	)
	(arc
		(start 91.731846 -269.707868)
		(mid 91.544648 -269.758011)
		(end 91.35745 -269.707868)
		(width 0.088646)
		(layer "In4.Cu")
		(net "M_C_CPU1_SA_DQ<18>")
	)
	(arc
		(start 90.417396 -269.707868)
		(mid 90.134694 -269.632126)
		(end 89.851992 -269.707868)
		(width 0.088646)
		(layer "In4.Cu")
		(net "M_C_CPU1_SA_DQ<18>")
	)
	(arc
		(start 90.791792 -269.707868)
		(mid 90.604594 -269.758011)
		(end 90.417396 -269.707868)
		(width 0.088646)
		(layer "In4.Cu")
		(net "M_C_CPU1_SA_DQ<18>")
	)
	(arc
		(start 89.851992 -269.707868)
		(mid 89.664794 -269.758011)
		(end 89.477596 -269.707868)
		(width 0.088646)
		(layer "In4.Cu")
		(net "M_C_CPU1_SA_DQ<18>")
	)
	(arc
		(start 87.597996 -269.707868)
		(mid 87.315294 -269.632126)
		(end 87.032592 -269.707868)
		(width 0.088646)
		(layer "In4.Cu")
		(net "M_C_CPU1_SA_DQ<18>")
	)
	(arc
		(start 92.19565 -268.897608)
		(mid 91.993063 -269.103959)
		(end 91.919044 -269.38351)
		(width 0.088646)
		(layer "In4.Cu")
		(net "M_C_CPU1_SA_DQ<18>")
	)
	(arc
		(start 91.347036 -269.701772)
		(mid 91.068604 -269.631958)
		(end 90.791792 -269.707868)
		(width 0.088646)
		(layer "In4.Cu")
		(net "M_C_CPU1_SA_DQ<18>")
	)
	(arc
		(start 91.919044 -269.392146)
		(mid 91.866774 -269.574511)
		(end 91.731846 -269.707868)
		(width 0.088646)
		(layer "In4.Cu")
		(net "M_C_CPU1_SA_DQ<18>")
	)
	(arc
		(start 92.76715 -268.894052)
		(mid 92.492951 -268.818217)
		(end 92.216478 -268.885416)
		(width 0.088646)
		(layer "In4.Cu")
		(net "M_C_CPU1_SA_DQ<18>")
	)
	(arc
		(start 93.045788 -269.317978)
		(mid 92.9567 -269.072993)
		(end 92.76715 -268.894052)
		(width 0.088646)
		(layer "In4.Cu")
		(net "M_C_CPU1_SA_DQ<18>")
	)
	(arc
		(start 85.718396 -269.707868)
		(mid 85.677466 -269.680835)
		(end 85.640418 -269.648686)
		(width 0.088646)
		(layer "In4.Cu")
		(net "M_C_CPU1_SA_DQ<18>")
	)
	(arc
		(start 86.658196 -269.707868)
		(mid 86.375494 -269.632126)
		(end 86.092792 -269.707868)
		(width 0.088646)
		(layer "In4.Cu")
		(net "M_C_CPU1_SA_DQ<18>")
	)
	(arc
		(start 87.032592 -269.707868)
		(mid 86.845394 -269.758011)
		(end 86.658196 -269.707868)
		(width 0.088646)
		(layer "In4.Cu")
		(net "M_C_CPU1_SA_DQ<18>")
	)
	(arc
		(start 87.972392 -269.707868)
		(mid 87.785194 -269.758011)
		(end 87.597996 -269.707868)
		(width 0.088646)
		(layer "In4.Cu")
		(net "M_C_CPU1_SA_DQ<18>")
	)
	(segment
		(start 25.432512 -295.645332)
		(end 25.595072 -295.482772)
		(width 0.20066)
		(layer "F.Cu")
		(net "M_C_CPU1_SA_DQ<17>")
	)
	(segment
		(start 28.198318 -295.491662)
		(end 28.529026 -295.491662)
		(width 0.101854)
		(layer "F.Cu")
		(net "M_C_CPU1_SA_DQ<17>")
	)
	(segment
		(start 23.228046 -295.916604)
		(end 24.562308 -295.916604)
		(width 0.20066)
		(layer "F.Cu")
		(net "M_C_CPU1_SA_DQ<17>")
	)
	(segment
		(start 25.432512 -295.9735)
		(end 25.432512 -295.645332)
		(width 0.20066)
		(layer "F.Cu")
		(net "M_C_CPU1_SA_DQ<17>")
	)
	(segment
		(start 28.529026 -295.491662)
		(end 28.707588 -295.491662)
		(width 0.20066)
		(layer "F.Cu")
		(net "M_C_CPU1_SA_DQ<17>")
	)
	(segment
		(start 25.27808 -296.127932)
		(end 25.432512 -295.9735)
		(width 0.20066)
		(layer "F.Cu")
		(net "M_C_CPU1_SA_DQ<17>")
	)
	(segment
		(start 92.014294 -268.033754)
		(end 92.014548 -268.034008)
		(width 0.20066)
		(layer "F.Cu")
		(net "M_C_CPU1_SA_DQ<17>")
	)
	(segment
		(start 24.773636 -296.127932)
		(end 25.27808 -296.127932)
		(width 0.20066)
		(layer "F.Cu")
		(net "M_C_CPU1_SA_DQ<17>")
	)
	(segment
		(start 29.13253 -295.916604)
		(end 30.771846 -295.916604)
		(width 0.20066)
		(layer "F.Cu")
		(net "M_C_CPU1_SA_DQ<17>")
	)
	(segment
		(start 25.595072 -295.482772)
		(end 26.20391 -295.482772)
		(width 0.20066)
		(layer "F.Cu")
		(net "M_C_CPU1_SA_DQ<17>")
	)
	(segment
		(start 26.20391 -295.482772)
		(end 26.2128 -295.491662)
		(width 0.1016)
		(layer "F.Cu")
		(net "M_C_CPU1_SA_DQ<17>")
	)
	(segment
		(start 92.014548 -268.034008)
		(end 92.014548 -268.569694)
		(width 0.20066)
		(layer "F.Cu")
		(net "M_C_CPU1_SA_DQ<17>")
	)
	(segment
		(start 24.562308 -295.916604)
		(end 24.773636 -296.127932)
		(width 0.20066)
		(layer "F.Cu")
		(net "M_C_CPU1_SA_DQ<17>")
	)
	(segment
		(start 31.876746 -295.916604)
		(end 30.771846 -295.916604)
		(width 0.20066)
		(layer "F.Cu")
		(net "M_C_CPU1_SA_DQ<17>")
	)
	(segment
		(start 28.707588 -295.491662)
		(end 29.13253 -295.916604)
		(width 0.20066)
		(layer "F.Cu")
		(net "M_C_CPU1_SA_DQ<17>")
	)
	(segment
		(start 26.2128 -295.491662)
		(end 28.198318 -295.491662)
		(width 0.1016)
		(layer "F.Cu")
		(net "M_C_CPU1_SA_DQ<17>")
	)
	(segment
		(start 88.912446 -269.059152)
		(end 88.906604 -269.05585)
		(width 0.088646)
		(layer "In4.Cu")
		(net "M_C_CPU1_SA_DQ<17>")
	)
	(segment
		(start 43.630596 -296.342054)
		(end 36.280852 -296.342054)
		(width 0.18288)
		(layer "In4.Cu")
		(net "M_C_CPU1_SA_DQ<17>")
	)
	(segment
		(start 63.401194 -291.01923)
		(end 62.408562 -292.011862)
		(width 0.18288)
		(layer "In4.Cu")
		(net "M_C_CPU1_SA_DQ<17>")
	)
	(segment
		(start 49.863756 -295.998138)
		(end 49.703736 -296.158158)
		(width 0.18288)
		(layer "In4.Cu")
		(net "M_C_CPU1_SA_DQ<17>")
	)
	(segment
		(start 32.302958 -296.342816)
		(end 31.876746 -295.916604)
		(width 0.18288)
		(layer "In4.Cu")
		(net "M_C_CPU1_SA_DQ<17>")
	)
	(segment
		(start 51.856132 -296.339514)
		(end 50.558954 -296.339514)
		(width 0.18288)
		(layer "In4.Cu")
		(net "M_C_CPU1_SA_DQ<17>")
	)
	(segment
		(start 62.408562 -292.011862)
		(end 61.70676 -292.011862)
		(width 0.18288)
		(layer "In4.Cu")
		(net "M_C_CPU1_SA_DQ<17>")
	)
	(segment
		(start 49.703736 -296.158158)
		(end 49.703736 -296.177716)
		(width 0.18288)
		(layer "In4.Cu")
		(net "M_C_CPU1_SA_DQ<17>")
	)
	(segment
		(start 56.741568 -294.783764)
		(end 55.485284 -294.783764)
		(width 0.18288)
		(layer "In4.Cu")
		(net "M_C_CPU1_SA_DQ<17>")
	)
	(segment
		(start 87.976202 -269.061184)
		(end 87.972646 -269.059152)
		(width 0.088646)
		(layer "In4.Cu")
		(net "M_C_CPU1_SA_DQ<17>")
	)
	(segment
		(start 54.078124 -294.499792)
		(end 52.508658 -296.069258)
		(width 0.18288)
		(layer "In4.Cu")
		(net "M_C_CPU1_SA_DQ<17>")
	)
	(segment
		(start 84.20608 -270.045434)
		(end 83.629754 -270.62176)
		(width 0.088646)
		(layer "In4.Cu")
		(net "M_C_CPU1_SA_DQ<17>")
	)
	(segment
		(start 47.478696 -297.192954)
		(end 44.481496 -297.192954)
		(width 0.18288)
		(layer "In4.Cu")
		(net "M_C_CPU1_SA_DQ<17>")
	)
	(segment
		(start 89.855802 -269.061184)
		(end 89.852246 -269.059152)
		(width 0.088646)
		(layer "In4.Cu")
		(net "M_C_CPU1_SA_DQ<17>")
	)
	(segment
		(start 44.481496 -297.192954)
		(end 43.630596 -296.342054)
		(width 0.18288)
		(layer "In4.Cu")
		(net "M_C_CPU1_SA_DQ<17>")
	)
	(segment
		(start 36.280852 -296.342054)
		(end 36.280598 -296.3418)
		(width 0.18288)
		(layer "In4.Cu")
		(net "M_C_CPU1_SA_DQ<17>")
	)
	(segment
		(start 64.975994 -291.460682)
		(end 64.749426 -291.460682)
		(width 0.18288)
		(layer "In4.Cu")
		(net "M_C_CPU1_SA_DQ<17>")
	)
	(segment
		(start 70.07352 -286.963358)
		(end 66.571876 -290.465002)
		(width 0.18288)
		(layer "In4.Cu")
		(net "M_C_CPU1_SA_DQ<17>")
	)
	(segment
		(start 64.589406 -291.300662)
		(end 64.589406 -291.17925)
		(width 0.18288)
		(layer "In4.Cu")
		(net "M_C_CPU1_SA_DQ<17>")
	)
	(segment
		(start 61.70676 -292.011862)
		(end 60.30087 -293.417752)
		(width 0.18288)
		(layer "In4.Cu")
		(net "M_C_CPU1_SA_DQ<17>")
	)
	(segment
		(start 65.971674 -290.465002)
		(end 64.975994 -291.460682)
		(width 0.18288)
		(layer "In4.Cu")
		(net "M_C_CPU1_SA_DQ<17>")
	)
	(segment
		(start 84.534502 -269.40129)
		(end 84.20608 -269.729712)
		(width 0.088646)
		(layer "In4.Cu")
		(net "M_C_CPU1_SA_DQ<17>")
	)
	(segment
		(start 52.508658 -296.069258)
		(end 51.856132 -296.339514)
		(width 0.18288)
		(layer "In4.Cu")
		(net "M_C_CPU1_SA_DQ<17>")
	)
	(segment
		(start 35.779202 -296.3418)
		(end 35.777932 -296.34307)
		(width 0.18288)
		(layer "In4.Cu")
		(net "M_C_CPU1_SA_DQ<17>")
	)
	(segment
		(start 50.397156 -296.177716)
		(end 50.397156 -296.158158)
		(width 0.18288)
		(layer "In4.Cu")
		(net "M_C_CPU1_SA_DQ<17>")
	)
	(segment
		(start 83.318604 -270.62176)
		(end 82.921602 -270.62176)
		(width 0.18288)
		(layer "In4.Cu")
		(net "M_C_CPU1_SA_DQ<17>")
	)
	(segment
		(start 84.20608 -269.729712)
		(end 84.20608 -270.045434)
		(width 0.088646)
		(layer "In4.Cu")
		(net "M_C_CPU1_SA_DQ<17>")
	)
	(segment
		(start 60.30087 -293.417752)
		(end 59.900058 -293.583868)
		(width 0.18288)
		(layer "In4.Cu")
		(net "M_C_CPU1_SA_DQ<17>")
	)
	(segment
		(start 64.429386 -291.01923)
		(end 63.401194 -291.01923)
		(width 0.18288)
		(layer "In4.Cu")
		(net "M_C_CPU1_SA_DQ<17>")
	)
	(segment
		(start 58.876438 -293.583868)
		(end 57.28081 -294.244522)
		(width 0.18288)
		(layer "In4.Cu")
		(net "M_C_CPU1_SA_DQ<17>")
	)
	(segment
		(start 90.792046 -269.059152)
		(end 90.786204 -269.05585)
		(width 0.088646)
		(layer "In4.Cu")
		(net "M_C_CPU1_SA_DQ<17>")
	)
	(segment
		(start 87.972646 -269.059152)
		(end 87.972392 -269.059152)
		(width 0.088646)
		(layer "In4.Cu")
		(net "M_C_CPU1_SA_DQ<17>")
	)
	(segment
		(start 64.589406 -291.17925)
		(end 64.429386 -291.01923)
		(width 0.18288)
		(layer "In4.Cu")
		(net "M_C_CPU1_SA_DQ<17>")
	)
	(segment
		(start 49.501552 -296.3799)
		(end 48.29175 -296.3799)
		(width 0.18288)
		(layer "In4.Cu")
		(net "M_C_CPU1_SA_DQ<17>")
	)
	(segment
		(start 90.797888 -269.062708)
		(end 90.792046 -269.059152)
		(width 0.088646)
		(layer "In4.Cu")
		(net "M_C_CPU1_SA_DQ<17>")
	)
	(segment
		(start 64.749426 -291.460682)
		(end 64.589406 -291.300662)
		(width 0.18288)
		(layer "In4.Cu")
		(net "M_C_CPU1_SA_DQ<17>")
	)
	(segment
		(start 35.777932 -296.34307)
		(end 35.26028 -296.34307)
		(width 0.18288)
		(layer "In4.Cu")
		(net "M_C_CPU1_SA_DQ<17>")
	)
	(segment
		(start 50.558954 -296.339514)
		(end 50.397156 -296.177716)
		(width 0.18288)
		(layer "In4.Cu")
		(net "M_C_CPU1_SA_DQ<17>")
	)
	(segment
		(start 50.237136 -295.998138)
		(end 49.863756 -295.998138)
		(width 0.18288)
		(layer "In4.Cu")
		(net "M_C_CPU1_SA_DQ<17>")
	)
	(segment
		(start 66.571876 -290.465002)
		(end 65.971674 -290.465002)
		(width 0.18288)
		(layer "In4.Cu")
		(net "M_C_CPU1_SA_DQ<17>")
	)
	(segment
		(start 48.29175 -296.3799)
		(end 47.478696 -297.192954)
		(width 0.18288)
		(layer "In4.Cu")
		(net "M_C_CPU1_SA_DQ<17>")
	)
	(segment
		(start 55.485284 -294.783764)
		(end 55.201312 -294.499792)
		(width 0.18288)
		(layer "In4.Cu")
		(net "M_C_CPU1_SA_DQ<17>")
	)
	(segment
		(start 88.917018 -269.061946)
		(end 88.912446 -269.059152)
		(width 0.088646)
		(layer "In4.Cu")
		(net "M_C_CPU1_SA_DQ<17>")
	)
	(segment
		(start 82.921602 -270.62176)
		(end 72.544178 -280.999184)
		(width 0.18288)
		(layer "In4.Cu")
		(net "M_C_CPU1_SA_DQ<17>")
	)
	(segment
		(start 59.900058 -293.583868)
		(end 58.876438 -293.583868)
		(width 0.18288)
		(layer "In4.Cu")
		(net "M_C_CPU1_SA_DQ<17>")
	)
	(segment
		(start 36.280598 -296.3418)
		(end 35.779202 -296.3418)
		(width 0.18288)
		(layer "In4.Cu")
		(net "M_C_CPU1_SA_DQ<17>")
	)
	(segment
		(start 83.629754 -270.62176)
		(end 83.318604 -270.62176)
		(width 0.088646)
		(layer "In4.Cu")
		(net "M_C_CPU1_SA_DQ<17>")
	)
	(segment
		(start 57.28081 -294.244522)
		(end 56.741568 -294.783764)
		(width 0.18288)
		(layer "In4.Cu")
		(net "M_C_CPU1_SA_DQ<17>")
	)
	(segment
		(start 55.201312 -294.499792)
		(end 54.078124 -294.499792)
		(width 0.18288)
		(layer "In4.Cu")
		(net "M_C_CPU1_SA_DQ<17>")
	)
	(segment
		(start 72.544178 -280.999184)
		(end 70.07352 -286.963358)
		(width 0.18288)
		(layer "In4.Cu")
		(net "M_C_CPU1_SA_DQ<17>")
	)
	(segment
		(start 49.703736 -296.177716)
		(end 49.501552 -296.3799)
		(width 0.18288)
		(layer "In4.Cu")
		(net "M_C_CPU1_SA_DQ<17>")
	)
	(segment
		(start 35.260026 -296.342816)
		(end 32.302958 -296.342816)
		(width 0.18288)
		(layer "In4.Cu")
		(net "M_C_CPU1_SA_DQ<17>")
	)
	(segment
		(start 91.437206 -269.012924)
		(end 91.357196 -269.059152)
		(width 0.088646)
		(layer "In4.Cu")
		(net "M_C_CPU1_SA_DQ<17>")
	)
	(segment
		(start 50.397156 -296.158158)
		(end 50.237136 -295.998138)
		(width 0.18288)
		(layer "In4.Cu")
		(net "M_C_CPU1_SA_DQ<17>")
	)
	(segment
		(start 35.26028 -296.34307)
		(end 35.260026 -296.342816)
		(width 0.18288)
		(layer "In4.Cu")
		(net "M_C_CPU1_SA_DQ<17>")
	)
	(arc
		(start 88.906604 -269.05585)
		(mid 88.721749 -269.0089)
		(end 88.537796 -269.059152)
		(width 0.088646)
		(layer "In4.Cu")
		(net "M_C_CPU1_SA_DQ<17>")
	)
	(arc
		(start 88.537796 -269.059152)
		(mid 88.257285 -269.134798)
		(end 87.976202 -269.061184)
		(width 0.088646)
		(layer "In4.Cu")
		(net "M_C_CPU1_SA_DQ<17>")
	)
	(arc
		(start 90.417396 -269.059152)
		(mid 90.136885 -269.134798)
		(end 89.855802 -269.061184)
		(width 0.088646)
		(layer "In4.Cu")
		(net "M_C_CPU1_SA_DQ<17>")
	)
	(arc
		(start 89.477596 -269.059152)
		(mid 89.197682 -269.134921)
		(end 88.917018 -269.061946)
		(width 0.088646)
		(layer "In4.Cu")
		(net "M_C_CPU1_SA_DQ<17>")
	)
	(arc
		(start 87.032592 -269.059152)
		(mid 86.845394 -269.009009)
		(end 86.658196 -269.059152)
		(width 0.088646)
		(layer "In4.Cu")
		(net "M_C_CPU1_SA_DQ<17>")
	)
	(arc
		(start 92.014548 -268.569694)
		(mid 91.740386 -268.81021)
		(end 91.437206 -269.012924)
		(width 0.088646)
		(layer "In4.Cu")
		(net "M_C_CPU1_SA_DQ<17>")
	)
	(arc
		(start 90.786204 -269.05585)
		(mid 90.601349 -269.0089)
		(end 90.417396 -269.059152)
		(width 0.088646)
		(layer "In4.Cu")
		(net "M_C_CPU1_SA_DQ<17>")
	)
	(arc
		(start 86.092792 -269.059152)
		(mid 85.905594 -269.009009)
		(end 85.718396 -269.059152)
		(width 0.088646)
		(layer "In4.Cu")
		(net "M_C_CPU1_SA_DQ<17>")
	)
	(arc
		(start 89.852246 -269.059152)
		(mid 89.664938 -269.009009)
		(end 89.477596 -269.059152)
		(width 0.088646)
		(layer "In4.Cu")
		(net "M_C_CPU1_SA_DQ<17>")
	)
	(arc
		(start 87.972392 -269.059152)
		(mid 87.785194 -269.009009)
		(end 87.597996 -269.059152)
		(width 0.088646)
		(layer "In4.Cu")
		(net "M_C_CPU1_SA_DQ<17>")
	)
	(arc
		(start 91.357196 -269.059152)
		(mid 91.078022 -269.134917)
		(end 90.797888 -269.062708)
		(width 0.088646)
		(layer "In4.Cu")
		(net "M_C_CPU1_SA_DQ<17>")
	)
	(arc
		(start 87.597996 -269.059152)
		(mid 87.315294 -269.134928)
		(end 87.032592 -269.059152)
		(width 0.088646)
		(layer "In4.Cu")
		(net "M_C_CPU1_SA_DQ<17>")
	)
	(arc
		(start 84.61629 -269.366746)
		(mid 84.572015 -269.376036)
		(end 84.534502 -269.40129)
		(width 0.088646)
		(layer "In4.Cu")
		(net "M_C_CPU1_SA_DQ<17>")
	)
	(arc
		(start 86.658196 -269.059152)
		(mid 86.375494 -269.134928)
		(end 86.092792 -269.059152)
		(width 0.088646)
		(layer "In4.Cu")
		(net "M_C_CPU1_SA_DQ<17>")
	)
	(arc
		(start 85.718396 -269.059152)
		(mid 85.18679 -269.282634)
		(end 84.61629 -269.366746)
		(width 0.088646)
		(layer "In4.Cu")
		(net "M_C_CPU1_SA_DQ<17>")
	)
	(segment
		(start 25.432512 -297.682666)
		(end 25.432512 -297.393106)
		(width 0.20066)
		(layer "F.Cu")
		(net "M_C_CPU1_SA_DQ<16>")
	)
	(segment
		(start 29.402786 -297.616626)
		(end 30.771846 -297.616626)
		(width 0.20066)
		(layer "F.Cu")
		(net "M_C_CPU1_SA_DQ<16>")
	)
	(segment
		(start 24.562308 -297.616626)
		(end 24.801068 -297.855386)
		(width 0.20066)
		(layer "F.Cu")
		(net "M_C_CPU1_SA_DQ<16>")
	)
	(segment
		(start 26.459942 -297.191684)
		(end 28.529026 -297.191684)
		(width 0.1016)
		(layer "F.Cu")
		(net "M_C_CPU1_SA_DQ<16>")
	)
	(segment
		(start 28.977844 -297.191684)
		(end 29.402786 -297.616626)
		(width 0.20066)
		(layer "F.Cu")
		(net "M_C_CPU1_SA_DQ<16>")
	)
	(segment
		(start 31.876746 -297.616626)
		(end 30.771846 -297.616626)
		(width 0.20066)
		(layer "F.Cu")
		(net "M_C_CPU1_SA_DQ<16>")
	)
	(segment
		(start 25.642062 -297.183556)
		(end 26.20391 -297.183556)
		(width 0.20066)
		(layer "F.Cu")
		(net "M_C_CPU1_SA_DQ<16>")
	)
	(segment
		(start 26.212038 -297.191684)
		(end 26.459942 -297.191684)
		(width 0.101854)
		(layer "F.Cu")
		(net "M_C_CPU1_SA_DQ<16>")
	)
	(segment
		(start 23.228046 -297.616626)
		(end 24.562308 -297.616626)
		(width 0.20066)
		(layer "F.Cu")
		(net "M_C_CPU1_SA_DQ<16>")
	)
	(segment
		(start 92.484194 -268.847824)
		(end 92.484194 -269.38351)
		(width 0.20066)
		(layer "F.Cu")
		(net "M_C_CPU1_SA_DQ<16>")
	)
	(segment
		(start 24.801068 -297.855386)
		(end 25.259792 -297.855386)
		(width 0.20066)
		(layer "F.Cu")
		(net "M_C_CPU1_SA_DQ<16>")
	)
	(segment
		(start 25.259792 -297.855386)
		(end 25.432512 -297.682666)
		(width 0.20066)
		(layer "F.Cu")
		(net "M_C_CPU1_SA_DQ<16>")
	)
	(segment
		(start 26.20391 -297.183556)
		(end 26.212038 -297.191684)
		(width 0.101854)
		(layer "F.Cu")
		(net "M_C_CPU1_SA_DQ<16>")
	)
	(segment
		(start 92.484448 -268.84757)
		(end 92.484194 -268.847824)
		(width 0.20066)
		(layer "F.Cu")
		(net "M_C_CPU1_SA_DQ<16>")
	)
	(segment
		(start 28.529026 -297.191684)
		(end 28.977844 -297.191684)
		(width 0.20066)
		(layer "F.Cu")
		(net "M_C_CPU1_SA_DQ<16>")
	)
	(segment
		(start 25.432512 -297.393106)
		(end 25.642062 -297.183556)
		(width 0.20066)
		(layer "F.Cu")
		(net "M_C_CPU1_SA_DQ<16>")
	)
	(segment
		(start 59.18581 -295.00576)
		(end 58.395108 -295.33342)
		(width 0.18288)
		(layer "In4.Cu")
		(net "M_C_CPU1_SA_DQ<16>")
	)
	(segment
		(start 61.335666 -293.838122)
		(end 60.79744 -294.376348)
		(width 0.18288)
		(layer "In4.Cu")
		(net "M_C_CPU1_SA_DQ<16>")
	)
	(segment
		(start 83.658202 -271.61744)
		(end 83.484466 -271.61744)
		(width 0.088646)
		(layer "In4.Cu")
		(net "M_C_CPU1_SA_DQ<16>")
	)
	(segment
		(start 54.136798 -296.343832)
		(end 52.438554 -298.042076)
		(width 0.18288)
		(layer "In4.Cu")
		(net "M_C_CPU1_SA_DQ<16>")
	)
	(segment
		(start 92.484194 -269.38351)
		(end 92.489782 -269.389098)
		(width 0.088646)
		(layer "In4.Cu")
		(net "M_C_CPU1_SA_DQ<16>")
	)
	(segment
		(start 85.85835 -269.946882)
		(end 85.32876 -269.946882)
		(width 0.088646)
		(layer "In4.Cu")
		(net "M_C_CPU1_SA_DQ<16>")
	)
	(segment
		(start 90.332306 -269.879318)
		(end 90.321892 -269.873222)
		(width 0.088646)
		(layer "In4.Cu")
		(net "M_C_CPU1_SA_DQ<16>")
	)
	(segment
		(start 56.792622 -296.343832)
		(end 54.136798 -296.343832)
		(width 0.18288)
		(layer "In4.Cu")
		(net "M_C_CPU1_SA_DQ<16>")
	)
	(segment
		(start 73.461626 -281.491182)
		(end 70.892924 -287.69183)
		(width 0.18288)
		(layer "In4.Cu")
		(net "M_C_CPU1_SA_DQ<16>")
	)
	(segment
		(start 50.558192 -298.042076)
		(end 50.055018 -298.54525)
		(width 0.18288)
		(layer "In4.Cu")
		(net "M_C_CPU1_SA_DQ<16>")
	)
	(segment
		(start 91.827096 -269.873222)
		(end 91.816682 -269.879318)
		(width 0.088646)
		(layer "In4.Cu")
		(net "M_C_CPU1_SA_DQ<16>")
	)
	(segment
		(start 47.868078 -298.54525)
		(end 47.523654 -298.889674)
		(width 0.18288)
		(layer "In4.Cu")
		(net "M_C_CPU1_SA_DQ<16>")
	)
	(segment
		(start 92.680282 -269.064232)
		(end 92.671392 -269.059152)
		(width 0.088646)
		(layer "In4.Cu")
		(net "M_C_CPU1_SA_DQ<16>")
	)
	(segment
		(start 50.055018 -298.54525)
		(end 47.868078 -298.54525)
		(width 0.18288)
		(layer "In4.Cu")
		(net "M_C_CPU1_SA_DQ<16>")
	)
	(segment
		(start 44.309792 -298.889674)
		(end 43.46194 -298.041822)
		(width 0.18288)
		(layer "In4.Cu")
		(net "M_C_CPU1_SA_DQ<16>")
	)
	(segment
		(start 70.892924 -287.69183)
		(end 65.923414 -292.66134)
		(width 0.18288)
		(layer "In4.Cu")
		(net "M_C_CPU1_SA_DQ<16>")
	)
	(segment
		(start 83.484466 -271.61744)
		(end 83.335368 -271.61744)
		(width 0.18288)
		(layer "In4.Cu")
		(net "M_C_CPU1_SA_DQ<16>")
	)
	(segment
		(start 57.803034 -295.33342)
		(end 56.792622 -296.343832)
		(width 0.18288)
		(layer "In4.Cu")
		(net "M_C_CPU1_SA_DQ<16>")
	)
	(segment
		(start 60.79744 -294.376348)
		(end 60.256928 -294.60063)
		(width 0.18288)
		(layer "In4.Cu")
		(net "M_C_CPU1_SA_DQ<16>")
	)
	(segment
		(start 47.523654 -298.889674)
		(end 44.309792 -298.889674)
		(width 0.18288)
		(layer "In4.Cu")
		(net "M_C_CPU1_SA_DQ<16>")
	)
	(segment
		(start 59.726322 -294.60063)
		(end 59.495182 -294.696388)
		(width 0.18288)
		(layer "In4.Cu")
		(net "M_C_CPU1_SA_DQ<16>")
	)
	(segment
		(start 92.489782 -269.389098)
		(end 92.79128 -269.389098)
		(width 0.088646)
		(layer "In4.Cu")
		(net "M_C_CPU1_SA_DQ<16>")
	)
	(segment
		(start 52.438554 -298.042076)
		(end 50.558192 -298.042076)
		(width 0.18288)
		(layer "In4.Cu")
		(net "M_C_CPU1_SA_DQ<16>")
	)
	(segment
		(start 58.395108 -295.33342)
		(end 57.803034 -295.33342)
		(width 0.18288)
		(layer "In4.Cu")
		(net "M_C_CPU1_SA_DQ<16>")
	)
	(segment
		(start 43.46194 -298.041822)
		(end 32.301942 -298.041822)
		(width 0.18288)
		(layer "In4.Cu")
		(net "M_C_CPU1_SA_DQ<16>")
	)
	(segment
		(start 92.109798 -269.374874)
		(end 92.109798 -269.397734)
		(width 0.088646)
		(layer "In4.Cu")
		(net "M_C_CPU1_SA_DQ<16>")
	)
	(segment
		(start 32.301942 -298.041822)
		(end 31.876746 -297.616626)
		(width 0.18288)
		(layer "In4.Cu")
		(net "M_C_CPU1_SA_DQ<16>")
	)
	(segment
		(start 64.178434 -292.66134)
		(end 61.335666 -293.838122)
		(width 0.18288)
		(layer "In4.Cu")
		(net "M_C_CPU1_SA_DQ<16>")
	)
	(segment
		(start 59.495182 -294.696388)
		(end 59.18581 -295.00576)
		(width 0.18288)
		(layer "In4.Cu")
		(net "M_C_CPU1_SA_DQ<16>")
	)
	(segment
		(start 65.923414 -292.66134)
		(end 64.178434 -292.66134)
		(width 0.18288)
		(layer "In4.Cu")
		(net "M_C_CPU1_SA_DQ<16>")
	)
	(segment
		(start 83.335368 -271.61744)
		(end 73.461626 -281.491182)
		(width 0.18288)
		(layer "In4.Cu")
		(net "M_C_CPU1_SA_DQ<16>")
	)
	(segment
		(start 92.79128 -269.389098)
		(end 92.854272 -269.326106)
		(width 0.088646)
		(layer "In4.Cu")
		(net "M_C_CPU1_SA_DQ<16>")
	)
	(segment
		(start 60.256928 -294.60063)
		(end 59.726322 -294.60063)
		(width 0.18288)
		(layer "In4.Cu")
		(net "M_C_CPU1_SA_DQ<16>")
	)
	(segment
		(start 85.32876 -269.946882)
		(end 83.658202 -271.61744)
		(width 0.088646)
		(layer "In4.Cu")
		(net "M_C_CPU1_SA_DQ<16>")
	)
	(arc
		(start 90.321892 -269.873222)
		(mid 90.134694 -269.823079)
		(end 89.947496 -269.873222)
		(width 0.088646)
		(layer "In4.Cu")
		(net "M_C_CPU1_SA_DQ<16>")
	)
	(arc
		(start 91.261946 -269.873222)
		(mid 91.074748 -269.823079)
		(end 90.88755 -269.873222)
		(width 0.088646)
		(layer "In4.Cu")
		(net "M_C_CPU1_SA_DQ<16>")
	)
	(arc
		(start 89.382092 -269.873222)
		(mid 89.194894 -269.823079)
		(end 89.007696 -269.873222)
		(width 0.088646)
		(layer "In4.Cu")
		(net "M_C_CPU1_SA_DQ<16>")
	)
	(arc
		(start 87.502492 -269.873222)
		(mid 87.315294 -269.823079)
		(end 87.128096 -269.873222)
		(width 0.088646)
		(layer "In4.Cu")
		(net "M_C_CPU1_SA_DQ<16>")
	)
	(arc
		(start 88.442292 -269.873222)
		(mid 88.255094 -269.823079)
		(end 88.067896 -269.873222)
		(width 0.088646)
		(layer "In4.Cu")
		(net "M_C_CPU1_SA_DQ<16>")
	)
	(arc
		(start 92.671392 -269.059152)
		(mid 92.484194 -269.009009)
		(end 92.296996 -269.059152)
		(width 0.088646)
		(layer "In4.Cu")
		(net "M_C_CPU1_SA_DQ<16>")
	)
	(arc
		(start 92.296996 -269.059152)
		(mid 92.162063 -269.192506)
		(end 92.109798 -269.374874)
		(width 0.088646)
		(layer "In4.Cu")
		(net "M_C_CPU1_SA_DQ<16>")
	)
	(arc
		(start 89.947496 -269.873222)
		(mid 89.664794 -269.948964)
		(end 89.382092 -269.873222)
		(width 0.088646)
		(layer "In4.Cu")
		(net "M_C_CPU1_SA_DQ<16>")
	)
	(arc
		(start 86.562692 -269.873222)
		(mid 86.375494 -269.823079)
		(end 86.188296 -269.873222)
		(width 0.088646)
		(layer "In4.Cu")
		(net "M_C_CPU1_SA_DQ<16>")
	)
	(arc
		(start 92.854272 -269.326106)
		(mid 92.796116 -269.175993)
		(end 92.680282 -269.064232)
		(width 0.088646)
		(layer "In4.Cu")
		(net "M_C_CPU1_SA_DQ<16>")
	)
	(arc
		(start 87.128096 -269.873222)
		(mid 86.845394 -269.948964)
		(end 86.562692 -269.873222)
		(width 0.088646)
		(layer "In4.Cu")
		(net "M_C_CPU1_SA_DQ<16>")
	)
	(arc
		(start 92.109798 -269.397734)
		(mid 92.030579 -269.672419)
		(end 91.827096 -269.873222)
		(width 0.088646)
		(layer "In4.Cu")
		(net "M_C_CPU1_SA_DQ<16>")
	)
	(arc
		(start 86.188296 -269.873222)
		(mid 86.028956 -269.93527)
		(end 85.85835 -269.946882)
		(width 0.088646)
		(layer "In4.Cu")
		(net "M_C_CPU1_SA_DQ<16>")
	)
	(arc
		(start 89.007696 -269.873222)
		(mid 88.724994 -269.948964)
		(end 88.442292 -269.873222)
		(width 0.088646)
		(layer "In4.Cu")
		(net "M_C_CPU1_SA_DQ<16>")
	)
	(arc
		(start 91.816682 -269.879318)
		(mid 91.538504 -269.94901)
		(end 91.261946 -269.873222)
		(width 0.088646)
		(layer "In4.Cu")
		(net "M_C_CPU1_SA_DQ<16>")
	)
	(arc
		(start 90.88755 -269.873222)
		(mid 90.610737 -269.949058)
		(end 90.332306 -269.879318)
		(width 0.088646)
		(layer "In4.Cu")
		(net "M_C_CPU1_SA_DQ<16>")
	)
	(arc
		(start 88.067896 -269.873222)
		(mid 87.785194 -269.948964)
		(end 87.502492 -269.873222)
		(width 0.088646)
		(layer "In4.Cu")
		(net "M_C_CPU1_SA_DQ<16>")
	)
	(segment
		(start 29.151326 -298.763436)
		(end 29.29382 -298.90593)
		(width 0.20066)
		(layer "F.Cu")
		(net "M_C_CPU1_SA_DQ<15>")
	)
	(segment
		(start 33.401762 -298.674282)
		(end 33.848294 -298.674282)
		(width 0.20066)
		(layer "F.Cu")
		(net "M_C_CPU1_SA_DQ<15>")
	)
	(segment
		(start 31.972758 -298.891706)
		(end 32.51708 -298.891706)
		(width 0.20066)
		(layer "F.Cu")
		(net "M_C_CPU1_SA_DQ<15>")
	)
	(segment
		(start 29.29382 -298.90593)
		(end 29.647642 -298.90593)
		(width 0.20066)
		(layer "F.Cu")
		(net "M_C_CPU1_SA_DQ<15>")
	)
	(segment
		(start 32.666178 -298.742608)
		(end 32.666178 -298.59097)
		(width 0.20066)
		(layer "F.Cu")
		(net "M_C_CPU1_SA_DQ<15>")
	)
	(segment
		(start 33.189926 -298.462446)
		(end 33.401762 -298.674282)
		(width 0.20066)
		(layer "F.Cu")
		(net "M_C_CPU1_SA_DQ<15>")
	)
	(segment
		(start 27.328114 -298.466764)
		(end 29.025342 -298.466764)
		(width 0.20066)
		(layer "F.Cu")
		(net "M_C_CPU1_SA_DQ<15>")
	)
	(segment
		(start 29.899864 -298.891706)
		(end 31.972758 -298.891706)
		(width 0.1016)
		(layer "F.Cu")
		(net "M_C_CPU1_SA_DQ<15>")
	)
	(segment
		(start 96.713294 -268.033754)
		(end 96.713548 -268.034008)
		(width 0.20066)
		(layer "F.Cu")
		(net "M_C_CPU1_SA_DQ<15>")
	)
	(segment
		(start 29.151326 -298.592748)
		(end 29.151326 -298.763436)
		(width 0.20066)
		(layer "F.Cu")
		(net "M_C_CPU1_SA_DQ<15>")
	)
	(segment
		(start 34.055812 -298.466764)
		(end 34.871914 -298.466764)
		(width 0.20066)
		(layer "F.Cu")
		(net "M_C_CPU1_SA_DQ<15>")
	)
	(segment
		(start 29.661866 -298.891706)
		(end 29.899864 -298.891706)
		(width 0.101854)
		(layer "F.Cu")
		(net "M_C_CPU1_SA_DQ<15>")
	)
	(segment
		(start 29.025342 -298.466764)
		(end 29.151326 -298.592748)
		(width 0.20066)
		(layer "F.Cu")
		(net "M_C_CPU1_SA_DQ<15>")
	)
	(segment
		(start 96.713548 -268.034008)
		(end 96.713548 -268.569694)
		(width 0.20066)
		(layer "F.Cu")
		(net "M_C_CPU1_SA_DQ<15>")
	)
	(segment
		(start 32.794702 -298.462446)
		(end 33.189926 -298.462446)
		(width 0.20066)
		(layer "F.Cu")
		(net "M_C_CPU1_SA_DQ<15>")
	)
	(segment
		(start 29.647642 -298.90593)
		(end 29.661866 -298.891706)
		(width 0.101854)
		(layer "F.Cu")
		(net "M_C_CPU1_SA_DQ<15>")
	)
	(segment
		(start 35.976814 -298.466764)
		(end 34.871914 -298.466764)
		(width 0.20066)
		(layer "F.Cu")
		(net "M_C_CPU1_SA_DQ<15>")
	)
	(segment
		(start 33.848294 -298.674282)
		(end 34.055812 -298.466764)
		(width 0.20066)
		(layer "F.Cu")
		(net "M_C_CPU1_SA_DQ<15>")
	)
	(segment
		(start 32.51708 -298.891706)
		(end 32.666178 -298.742608)
		(width 0.20066)
		(layer "F.Cu")
		(net "M_C_CPU1_SA_DQ<15>")
	)
	(segment
		(start 32.666178 -298.59097)
		(end 32.794702 -298.462446)
		(width 0.20066)
		(layer "F.Cu")
		(net "M_C_CPU1_SA_DQ<15>")
	)
	(segment
		(start 42.412412 -288.921952)
		(end 42.147998 -289.186366)
		(width 0.18288)
		(layer "In6.Cu")
		(net "M_C_CPU1_SA_DQ<15>")
	)
	(segment
		(start 56.458612 -285.468822)
		(end 55.428896 -285.468822)
		(width 0.18288)
		(layer "In6.Cu")
		(net "M_C_CPU1_SA_DQ<15>")
	)
	(segment
		(start 43.867324 -288.691828)
		(end 43.250866 -289.308286)
		(width 0.18288)
		(layer "In6.Cu")
		(net "M_C_CPU1_SA_DQ<15>")
	)
	(segment
		(start 38.28923 -292.751002)
		(end 38.28923 -293.009574)
		(width 0.18288)
		(layer "In6.Cu")
		(net "M_C_CPU1_SA_DQ<15>")
	)
	(segment
		(start 38.777926 -292.262306)
		(end 37.777928 -291.262308)
		(width 0.18288)
		(layer "In6.Cu")
		(net "M_C_CPU1_SA_DQ<15>")
	)
	(segment
		(start 85.117432 -269.37208)
		(end 84.52358 -269.37208)
		(width 0.088646)
		(layer "In6.Cu")
		(net "M_C_CPU1_SA_DQ<15>")
	)
	(segment
		(start 43.250866 -289.308286)
		(end 43.024806 -289.308286)
		(width 0.18288)
		(layer "In6.Cu")
		(net "M_C_CPU1_SA_DQ<15>")
	)
	(segment
		(start 45.06087 -287.982406)
		(end 45.06087 -288.531808)
		(width 0.18288)
		(layer "In6.Cu")
		(net "M_C_CPU1_SA_DQ<15>")
	)
	(segment
		(start 45.22089 -287.822386)
		(end 45.06087 -287.982406)
		(width 0.18288)
		(layer "In6.Cu")
		(net "M_C_CPU1_SA_DQ<15>")
	)
	(segment
		(start 93.236796 -268.080236)
		(end 93.222064 -268.0716)
		(width 0.088646)
		(layer "In6.Cu")
		(net "M_C_CPU1_SA_DQ<15>")
	)
	(segment
		(start 36.615878 -297.8277)
		(end 35.976814 -298.466764)
		(width 0.18288)
		(layer "In6.Cu")
		(net "M_C_CPU1_SA_DQ<15>")
	)
	(segment
		(start 62.96025 -282.874974)
		(end 62.213998 -283.621226)
		(width 0.18288)
		(layer "In6.Cu")
		(net "M_C_CPU1_SA_DQ<15>")
	)
	(segment
		(start 40.819324 -290.47948)
		(end 39.036498 -292.262306)
		(width 0.18288)
		(layer "In6.Cu")
		(net "M_C_CPU1_SA_DQ<15>")
	)
	(segment
		(start 66.076576 -281.116786)
		(end 65.320164 -281.873198)
		(width 0.18288)
		(layer "In6.Cu")
		(net "M_C_CPU1_SA_DQ<15>")
	)
	(segment
		(start 84.18195 -269.71371)
		(end 84.18195 -270.352774)
		(width 0.088646)
		(layer "In6.Cu")
		(net "M_C_CPU1_SA_DQ<15>")
	)
	(segment
		(start 58.306208 -283.621226)
		(end 56.458612 -285.468822)
		(width 0.18288)
		(layer "In6.Cu")
		(net "M_C_CPU1_SA_DQ<15>")
	)
	(segment
		(start 83.342988 -270.936212)
		(end 82.44459 -270.936212)
		(width 0.18288)
		(layer "In6.Cu")
		(net "M_C_CPU1_SA_DQ<15>")
	)
	(segment
		(start 37.289232 -291.751004)
		(end 38.28923 -292.751002)
		(width 0.18288)
		(layer "In6.Cu")
		(net "M_C_CPU1_SA_DQ<15>")
	)
	(segment
		(start 96.062292 -268.083792)
		(end 96.056196 -268.080236)
		(width 0.088646)
		(layer "In6.Cu")
		(net "M_C_CPU1_SA_DQ<15>")
	)
	(segment
		(start 45.75429 -287.993328)
		(end 45.583348 -287.822386)
		(width 0.18288)
		(layer "In6.Cu")
		(net "M_C_CPU1_SA_DQ<15>")
	)
	(segment
		(start 42.534332 -289.79876)
		(end 42.534332 -290.02482)
		(width 0.18288)
		(layer "In6.Cu")
		(net "M_C_CPU1_SA_DQ<15>")
	)
	(segment
		(start 94.176596 -268.080236)
		(end 94.161864 -268.0716)
		(width 0.088646)
		(layer "In6.Cu")
		(net "M_C_CPU1_SA_DQ<15>")
	)
	(segment
		(start 37.777928 -291.262308)
		(end 37.519356 -291.262308)
		(width 0.18288)
		(layer "In6.Cu")
		(net "M_C_CPU1_SA_DQ<15>")
	)
	(segment
		(start 39.036498 -292.262306)
		(end 38.777926 -292.262306)
		(width 0.18288)
		(layer "In6.Cu")
		(net "M_C_CPU1_SA_DQ<15>")
	)
	(segment
		(start 63.502286 -281.873198)
		(end 62.96025 -282.415234)
		(width 0.18288)
		(layer "In6.Cu")
		(net "M_C_CPU1_SA_DQ<15>")
	)
	(segment
		(start 92.296996 -268.080236)
		(end 92.282264 -268.0716)
		(width 0.088646)
		(layer "In6.Cu")
		(net "M_C_CPU1_SA_DQ<15>")
	)
	(segment
		(start 82.44459 -270.936212)
		(end 73.813416 -274.5105)
		(width 0.18288)
		(layer "In6.Cu")
		(net "M_C_CPU1_SA_DQ<15>")
	)
	(segment
		(start 65.320164 -281.873198)
		(end 63.502286 -281.873198)
		(width 0.18288)
		(layer "In6.Cu")
		(net "M_C_CPU1_SA_DQ<15>")
	)
	(segment
		(start 96.056196 -268.080236)
		(end 96.041464 -268.0716)
		(width 0.088646)
		(layer "In6.Cu")
		(net "M_C_CPU1_SA_DQ<15>")
	)
	(segment
		(start 49.896268 -287.841436)
		(end 49.045876 -288.691828)
		(width 0.18288)
		(layer "In6.Cu")
		(net "M_C_CPU1_SA_DQ<15>")
	)
	(segment
		(start 67.20713 -281.116786)
		(end 66.076576 -281.116786)
		(width 0.18288)
		(layer "In6.Cu")
		(net "M_C_CPU1_SA_DQ<15>")
	)
	(segment
		(start 62.213998 -283.621226)
		(end 58.306208 -283.621226)
		(width 0.18288)
		(layer "In6.Cu")
		(net "M_C_CPU1_SA_DQ<15>")
	)
	(segment
		(start 49.045876 -288.691828)
		(end 45.91431 -288.691828)
		(width 0.18288)
		(layer "In6.Cu")
		(net "M_C_CPU1_SA_DQ<15>")
	)
	(segment
		(start 42.638472 -288.921952)
		(end 42.412412 -288.921952)
		(width 0.18288)
		(layer "In6.Cu")
		(net "M_C_CPU1_SA_DQ<15>")
	)
	(segment
		(start 84.52358 -269.37208)
		(end 84.18195 -269.71371)
		(width 0.088646)
		(layer "In6.Cu")
		(net "M_C_CPU1_SA_DQ<15>")
	)
	(segment
		(start 44.90085 -288.691828)
		(end 43.867324 -288.691828)
		(width 0.18288)
		(layer "In6.Cu")
		(net "M_C_CPU1_SA_DQ<15>")
	)
	(segment
		(start 62.96025 -282.415234)
		(end 62.96025 -282.874974)
		(width 0.18288)
		(layer "In6.Cu")
		(net "M_C_CPU1_SA_DQ<15>")
	)
	(segment
		(start 85.505798 -268.983714)
		(end 85.117432 -269.37208)
		(width 0.088646)
		(layer "In6.Cu")
		(net "M_C_CPU1_SA_DQ<15>")
	)
	(segment
		(start 54.613556 -286.284162)
		(end 54.130194 -286.284162)
		(width 0.18288)
		(layer "In6.Cu")
		(net "M_C_CPU1_SA_DQ<15>")
	)
	(segment
		(start 38.28923 -293.009574)
		(end 36.615878 -294.682926)
		(width 0.18288)
		(layer "In6.Cu")
		(net "M_C_CPU1_SA_DQ<15>")
	)
	(segment
		(start 45.06087 -288.531808)
		(end 44.90085 -288.691828)
		(width 0.18288)
		(layer "In6.Cu")
		(net "M_C_CPU1_SA_DQ<15>")
	)
	(segment
		(start 42.079672 -290.47948)
		(end 40.819324 -290.47948)
		(width 0.18288)
		(layer "In6.Cu")
		(net "M_C_CPU1_SA_DQ<15>")
	)
	(segment
		(start 45.91431 -288.691828)
		(end 45.75429 -288.531808)
		(width 0.18288)
		(layer "In6.Cu")
		(net "M_C_CPU1_SA_DQ<15>")
	)
	(segment
		(start 45.583348 -287.822386)
		(end 45.22089 -287.822386)
		(width 0.18288)
		(layer "In6.Cu")
		(net "M_C_CPU1_SA_DQ<15>")
	)
	(segment
		(start 85.810344 -268.559788)
		(end 85.810344 -268.569694)
		(width 0.088646)
		(layer "In6.Cu")
		(net "M_C_CPU1_SA_DQ<15>")
	)
	(segment
		(start 89.862406 -268.07414)
		(end 89.851992 -268.080236)
		(width 0.088646)
		(layer "In6.Cu")
		(net "M_C_CPU1_SA_DQ<15>")
	)
	(segment
		(start 37.289232 -291.492432)
		(end 37.289232 -291.751004)
		(width 0.18288)
		(layer "In6.Cu")
		(net "M_C_CPU1_SA_DQ<15>")
	)
	(segment
		(start 55.428896 -285.468822)
		(end 54.613556 -286.284162)
		(width 0.18288)
		(layer "In6.Cu")
		(net "M_C_CPU1_SA_DQ<15>")
	)
	(segment
		(start 83.598512 -270.936212)
		(end 83.342988 -270.936212)
		(width 0.088646)
		(layer "In6.Cu")
		(net "M_C_CPU1_SA_DQ<15>")
	)
	(segment
		(start 96.713548 -268.569694)
		(end 96.400874 -268.569694)
		(width 0.088646)
		(layer "In6.Cu")
		(net "M_C_CPU1_SA_DQ<15>")
	)
	(segment
		(start 42.534332 -290.02482)
		(end 42.079672 -290.47948)
		(width 0.18288)
		(layer "In6.Cu")
		(net "M_C_CPU1_SA_DQ<15>")
	)
	(segment
		(start 52.57292 -287.841436)
		(end 49.896268 -287.841436)
		(width 0.18288)
		(layer "In6.Cu")
		(net "M_C_CPU1_SA_DQ<15>")
	)
	(segment
		(start 91.357196 -268.080236)
		(end 91.346782 -268.07414)
		(width 0.088646)
		(layer "In6.Cu")
		(net "M_C_CPU1_SA_DQ<15>")
	)
	(segment
		(start 42.147998 -289.412426)
		(end 42.534332 -289.79876)
		(width 0.18288)
		(layer "In6.Cu")
		(net "M_C_CPU1_SA_DQ<15>")
	)
	(segment
		(start 43.024806 -289.308286)
		(end 42.638472 -288.921952)
		(width 0.18288)
		(layer "In6.Cu")
		(net "M_C_CPU1_SA_DQ<15>")
	)
	(segment
		(start 73.813416 -274.5105)
		(end 67.20713 -281.116786)
		(width 0.18288)
		(layer "In6.Cu")
		(net "M_C_CPU1_SA_DQ<15>")
	)
	(segment
		(start 45.75429 -288.531808)
		(end 45.75429 -287.993328)
		(width 0.18288)
		(layer "In6.Cu")
		(net "M_C_CPU1_SA_DQ<15>")
	)
	(segment
		(start 42.147998 -289.186366)
		(end 42.147998 -289.412426)
		(width 0.18288)
		(layer "In6.Cu")
		(net "M_C_CPU1_SA_DQ<15>")
	)
	(segment
		(start 37.519356 -291.262308)
		(end 37.289232 -291.492432)
		(width 0.18288)
		(layer "In6.Cu")
		(net "M_C_CPU1_SA_DQ<15>")
	)
	(segment
		(start 96.400874 -268.569694)
		(end 96.335088 -268.503908)
		(width 0.088646)
		(layer "In6.Cu")
		(net "M_C_CPU1_SA_DQ<15>")
	)
	(segment
		(start 36.615878 -294.682926)
		(end 36.615878 -297.8277)
		(width 0.18288)
		(layer "In6.Cu")
		(net "M_C_CPU1_SA_DQ<15>")
	)
	(segment
		(start 54.130194 -286.284162)
		(end 52.57292 -287.841436)
		(width 0.18288)
		(layer "In6.Cu")
		(net "M_C_CPU1_SA_DQ<15>")
	)
	(segment
		(start 84.18195 -270.352774)
		(end 83.598512 -270.936212)
		(width 0.088646)
		(layer "In6.Cu")
		(net "M_C_CPU1_SA_DQ<15>")
	)
	(arc
		(start 89.477596 -268.080236)
		(mid 89.194894 -268.00446)
		(end 88.912192 -268.080236)
		(width 0.088646)
		(layer "In6.Cu")
		(net "M_C_CPU1_SA_DQ<15>")
	)
	(arc
		(start 91.731592 -268.080236)
		(mid 91.544394 -268.130379)
		(end 91.357196 -268.080236)
		(width 0.088646)
		(layer "In6.Cu")
		(net "M_C_CPU1_SA_DQ<15>")
	)
	(arc
		(start 88.912192 -268.080236)
		(mid 88.724994 -268.130379)
		(end 88.537796 -268.080236)
		(width 0.088646)
		(layer "In6.Cu")
		(net "M_C_CPU1_SA_DQ<15>")
	)
	(arc
		(start 96.335088 -268.503908)
		(mid 96.2478 -268.261952)
		(end 96.062292 -268.083792)
		(width 0.088646)
		(layer "In6.Cu")
		(net "M_C_CPU1_SA_DQ<15>")
	)
	(arc
		(start 90.792046 -268.080236)
		(mid 90.604848 -268.130379)
		(end 90.41765 -268.080236)
		(width 0.088646)
		(layer "In6.Cu")
		(net "M_C_CPU1_SA_DQ<15>")
	)
	(arc
		(start 87.597996 -268.080236)
		(mid 87.315294 -268.00446)
		(end 87.032592 -268.080236)
		(width 0.088646)
		(layer "In6.Cu")
		(net "M_C_CPU1_SA_DQ<15>")
	)
	(arc
		(start 86.658196 -268.080236)
		(mid 86.375494 -268.00446)
		(end 86.092792 -268.080236)
		(width 0.088646)
		(layer "In6.Cu")
		(net "M_C_CPU1_SA_DQ<15>")
	)
	(arc
		(start 94.161864 -268.0716)
		(mid 93.885389 -268.00428)
		(end 93.611192 -268.080236)
		(width 0.088646)
		(layer "In6.Cu")
		(net "M_C_CPU1_SA_DQ<15>")
	)
	(arc
		(start 87.032592 -268.080236)
		(mid 86.845394 -268.130379)
		(end 86.658196 -268.080236)
		(width 0.088646)
		(layer "In6.Cu")
		(net "M_C_CPU1_SA_DQ<15>")
	)
	(arc
		(start 96.041464 -268.0716)
		(mid 95.764989 -268.00428)
		(end 95.490792 -268.080236)
		(width 0.088646)
		(layer "In6.Cu")
		(net "M_C_CPU1_SA_DQ<15>")
	)
	(arc
		(start 93.222064 -268.0716)
		(mid 92.945589 -268.00428)
		(end 92.671392 -268.080236)
		(width 0.088646)
		(layer "In6.Cu")
		(net "M_C_CPU1_SA_DQ<15>")
	)
	(arc
		(start 95.116396 -268.080236)
		(mid 94.833694 -268.00446)
		(end 94.550992 -268.080236)
		(width 0.088646)
		(layer "In6.Cu")
		(net "M_C_CPU1_SA_DQ<15>")
	)
	(arc
		(start 86.092792 -268.080236)
		(mid 85.888457 -268.282841)
		(end 85.810344 -268.559788)
		(width 0.088646)
		(layer "In6.Cu")
		(net "M_C_CPU1_SA_DQ<15>")
	)
	(arc
		(start 89.851992 -268.080236)
		(mid 89.664794 -268.130379)
		(end 89.477596 -268.080236)
		(width 0.088646)
		(layer "In6.Cu")
		(net "M_C_CPU1_SA_DQ<15>")
	)
	(arc
		(start 94.550992 -268.080236)
		(mid 94.363794 -268.130379)
		(end 94.176596 -268.080236)
		(width 0.088646)
		(layer "In6.Cu")
		(net "M_C_CPU1_SA_DQ<15>")
	)
	(arc
		(start 92.282264 -268.0716)
		(mid 92.005789 -268.00428)
		(end 91.731592 -268.080236)
		(width 0.088646)
		(layer "In6.Cu")
		(net "M_C_CPU1_SA_DQ<15>")
	)
	(arc
		(start 90.41765 -268.080236)
		(mid 90.140837 -268.004366)
		(end 89.862406 -268.07414)
		(width 0.088646)
		(layer "In6.Cu")
		(net "M_C_CPU1_SA_DQ<15>")
	)
	(arc
		(start 85.810344 -268.569694)
		(mid 85.762665 -268.752594)
		(end 85.631782 -268.888972)
		(width 0.088646)
		(layer "In6.Cu")
		(net "M_C_CPU1_SA_DQ<15>")
	)
	(arc
		(start 87.972392 -268.080236)
		(mid 87.785194 -268.130379)
		(end 87.597996 -268.080236)
		(width 0.088646)
		(layer "In6.Cu")
		(net "M_C_CPU1_SA_DQ<15>")
	)
	(arc
		(start 91.346782 -268.07414)
		(mid 91.068604 -268.004417)
		(end 90.792046 -268.080236)
		(width 0.088646)
		(layer "In6.Cu")
		(net "M_C_CPU1_SA_DQ<15>")
	)
	(arc
		(start 88.537796 -268.080236)
		(mid 88.255094 -268.00446)
		(end 87.972392 -268.080236)
		(width 0.088646)
		(layer "In6.Cu")
		(net "M_C_CPU1_SA_DQ<15>")
	)
	(arc
		(start 85.631782 -268.888972)
		(mid 85.565478 -268.931938)
		(end 85.505798 -268.983714)
		(width 0.088646)
		(layer "In6.Cu")
		(net "M_C_CPU1_SA_DQ<15>")
	)
	(arc
		(start 95.490792 -268.080236)
		(mid 95.303594 -268.130379)
		(end 95.116396 -268.080236)
		(width 0.088646)
		(layer "In6.Cu")
		(net "M_C_CPU1_SA_DQ<15>")
	)
	(arc
		(start 93.611192 -268.080236)
		(mid 93.423994 -268.130379)
		(end 93.236796 -268.080236)
		(width 0.088646)
		(layer "In6.Cu")
		(net "M_C_CPU1_SA_DQ<15>")
	)
	(arc
		(start 92.671392 -268.080236)
		(mid 92.484194 -268.130379)
		(end 92.296996 -268.080236)
		(width 0.088646)
		(layer "In6.Cu")
		(net "M_C_CPU1_SA_DQ<15>")
	)
	(segment
		(start 32.74949 -300.211236)
		(end 32.916876 -300.378622)
		(width 0.20066)
		(layer "F.Cu")
		(net "M_C_CPU1_SA_DQ<14>")
	)
	(segment
		(start 29.647642 -299.731684)
		(end 29.657802 -299.741844)
		(width 0.101854)
		(layer "F.Cu")
		(net "M_C_CPU1_SA_DQ<14>")
	)
	(segment
		(start 32.916876 -300.378622)
		(end 33.345374 -300.378622)
		(width 0.20066)
		(layer "F.Cu")
		(net "M_C_CPU1_SA_DQ<14>")
	)
	(segment
		(start 35.976814 -300.166786)
		(end 34.871914 -300.166786)
		(width 0.20066)
		(layer "F.Cu")
		(net "M_C_CPU1_SA_DQ<14>")
	)
	(segment
		(start 33.55721 -300.166786)
		(end 34.871914 -300.166786)
		(width 0.20066)
		(layer "F.Cu")
		(net "M_C_CPU1_SA_DQ<14>")
	)
	(segment
		(start 97.183448 -268.84757)
		(end 97.183194 -268.847824)
		(width 0.20066)
		(layer "F.Cu")
		(net "M_C_CPU1_SA_DQ<14>")
	)
	(segment
		(start 97.183194 -268.847824)
		(end 97.183194 -269.38351)
		(width 0.20066)
		(layer "F.Cu")
		(net "M_C_CPU1_SA_DQ<14>")
	)
	(segment
		(start 28.475178 -300.166786)
		(end 28.91028 -299.731684)
		(width 0.20066)
		(layer "F.Cu")
		(net "M_C_CPU1_SA_DQ<14>")
	)
	(segment
		(start 27.328114 -300.166786)
		(end 28.475178 -300.166786)
		(width 0.20066)
		(layer "F.Cu")
		(net "M_C_CPU1_SA_DQ<14>")
	)
	(segment
		(start 33.345374 -300.378622)
		(end 33.55721 -300.166786)
		(width 0.20066)
		(layer "F.Cu")
		(net "M_C_CPU1_SA_DQ<14>")
	)
	(segment
		(start 31.972758 -299.741844)
		(end 32.605726 -299.741844)
		(width 0.20066)
		(layer "F.Cu")
		(net "M_C_CPU1_SA_DQ<14>")
	)
	(segment
		(start 32.605726 -299.741844)
		(end 32.74949 -299.885608)
		(width 0.20066)
		(layer "F.Cu")
		(net "M_C_CPU1_SA_DQ<14>")
	)
	(segment
		(start 32.74949 -299.885608)
		(end 32.74949 -300.211236)
		(width 0.20066)
		(layer "F.Cu")
		(net "M_C_CPU1_SA_DQ<14>")
	)
	(segment
		(start 29.912818 -299.741844)
		(end 31.972758 -299.741844)
		(width 0.1016)
		(layer "F.Cu")
		(net "M_C_CPU1_SA_DQ<14>")
	)
	(segment
		(start 29.657802 -299.741844)
		(end 29.912818 -299.741844)
		(width 0.101854)
		(layer "F.Cu")
		(net "M_C_CPU1_SA_DQ<14>")
	)
	(segment
		(start 28.91028 -299.731684)
		(end 29.647642 -299.731684)
		(width 0.20066)
		(layer "F.Cu")
		(net "M_C_CPU1_SA_DQ<14>")
	)
	(segment
		(start 39.001446 -296.646092)
		(end 38.818566 -296.828972)
		(width 0.18288)
		(layer "In6.Cu")
		(net "M_C_CPU1_SA_DQ<14>")
	)
	(segment
		(start 42.591736 -291.71392)
		(end 42.431716 -291.5539)
		(width 0.18288)
		(layer "In6.Cu")
		(net "M_C_CPU1_SA_DQ<14>")
	)
	(segment
		(start 55.6895 -287.130744)
		(end 54.796436 -288.023808)
		(width 0.18288)
		(layer "In6.Cu")
		(net "M_C_CPU1_SA_DQ<14>")
	)
	(segment
		(start 39.000684 -294.092884)
		(end 38.237414 -294.856154)
		(width 0.18288)
		(layer "In6.Cu")
		(net "M_C_CPU1_SA_DQ<14>")
	)
	(segment
		(start 85.975698 -269.797784)
		(end 85.791802 -269.98168)
		(width 0.088646)
		(layer "In6.Cu")
		(net "M_C_CPU1_SA_DQ<14>")
	)
	(segment
		(start 86.280244 -269.373604)
		(end 86.280244 -269.38351)
		(width 0.088646)
		(layer "In6.Cu")
		(net "M_C_CPU1_SA_DQ<14>")
	)
	(segment
		(start 48.408844 -290.697412)
		(end 48.02124 -290.697412)
		(width 0.18288)
		(layer "In6.Cu")
		(net "M_C_CPU1_SA_DQ<14>")
	)
	(segment
		(start 42.431716 -291.5539)
		(end 42.083736 -291.5539)
		(width 0.18288)
		(layer "In6.Cu")
		(net "M_C_CPU1_SA_DQ<14>")
	)
	(segment
		(start 38.818566 -296.828972)
		(end 38.420294 -296.828972)
		(width 0.18288)
		(layer "In6.Cu")
		(net "M_C_CPU1_SA_DQ<14>")
	)
	(segment
		(start 39.001446 -297.702732)
		(end 39.001446 -298.027852)
		(width 0.18288)
		(layer "In6.Cu")
		(net "M_C_CPU1_SA_DQ<14>")
	)
	(segment
		(start 44.111418 -291.05987)
		(end 44.34967 -291.298122)
		(width 0.18288)
		(layer "In6.Cu")
		(net "M_C_CPU1_SA_DQ<14>")
	)
	(segment
		(start 65.569338 -282.880562)
		(end 65.031112 -283.418788)
		(width 0.18288)
		(layer "In6.Cu")
		(net "M_C_CPU1_SA_DQ<14>")
	)
	(segment
		(start 93.156278 -268.885416)
		(end 93.141546 -268.894052)
		(width 0.088646)
		(layer "In6.Cu")
		(net "M_C_CPU1_SA_DQ<14>")
	)
	(segment
		(start 38.237414 -295.955212)
		(end 38.420294 -296.138092)
		(width 0.18288)
		(layer "In6.Cu")
		(net "M_C_CPU1_SA_DQ<14>")
	)
	(segment
		(start 44.111418 -290.83381)
		(end 44.111418 -291.05987)
		(width 0.18288)
		(layer "In6.Cu")
		(net "M_C_CPU1_SA_DQ<14>")
	)
	(segment
		(start 59.011566 -285.424626)
		(end 58.226706 -285.424626)
		(width 0.18288)
		(layer "In6.Cu")
		(net "M_C_CPU1_SA_DQ<14>")
	)
	(segment
		(start 96.624902 -268.951964)
		(end 96.541844 -268.903196)
		(width 0.088646)
		(layer "In6.Cu")
		(net "M_C_CPU1_SA_DQ<14>")
	)
	(segment
		(start 38.818566 -297.519852)
		(end 39.001446 -297.702732)
		(width 0.18288)
		(layer "In6.Cu")
		(net "M_C_CPU1_SA_DQ<14>")
	)
	(segment
		(start 83.84667 -271.31264)
		(end 83.84667 -271.694148)
		(width 0.088646)
		(layer "In6.Cu")
		(net "M_C_CPU1_SA_DQ<14>")
	)
	(segment
		(start 49.113694 -290.391596)
		(end 48.71466 -290.391596)
		(width 0.18288)
		(layer "In6.Cu")
		(net "M_C_CPU1_SA_DQ<14>")
	)
	(segment
		(start 41.891458 -292.30701)
		(end 41.34231 -292.856158)
		(width 0.18288)
		(layer "In6.Cu")
		(net "M_C_CPU1_SA_DQ<14>")
	)
	(segment
		(start 38.818566 -298.210732)
		(end 38.420294 -298.210732)
		(width 0.18288)
		(layer "In6.Cu")
		(net "M_C_CPU1_SA_DQ<14>")
	)
	(segment
		(start 48.71466 -290.391596)
		(end 48.408844 -290.697412)
		(width 0.18288)
		(layer "In6.Cu")
		(net "M_C_CPU1_SA_DQ<14>")
	)
	(segment
		(start 38.420294 -298.210732)
		(end 38.237414 -298.393612)
		(width 0.18288)
		(layer "In6.Cu")
		(net "M_C_CPU1_SA_DQ<14>")
	)
	(segment
		(start 41.083738 -292.856412)
		(end 40.942514 -292.715188)
		(width 0.18288)
		(layer "In6.Cu")
		(net "M_C_CPU1_SA_DQ<14>")
	)
	(segment
		(start 82.564478 -271.964658)
		(end 74.804524 -275.179028)
		(width 0.18288)
		(layer "In6.Cu")
		(net "M_C_CPU1_SA_DQ<14>")
	)
	(segment
		(start 44.704 -290.241228)
		(end 44.111418 -290.83381)
		(width 0.18288)
		(layer "In6.Cu")
		(net "M_C_CPU1_SA_DQ<14>")
	)
	(segment
		(start 41.34231 -292.856158)
		(end 41.083738 -292.856412)
		(width 0.18288)
		(layer "In6.Cu")
		(net "M_C_CPU1_SA_DQ<14>")
	)
	(segment
		(start 84.733638 -270.425672)
		(end 83.84667 -271.31264)
		(width 0.088646)
		(layer "In6.Cu")
		(net "M_C_CPU1_SA_DQ<14>")
	)
	(segment
		(start 47.715424 -290.391596)
		(end 46.416722 -290.391596)
		(width 0.18288)
		(layer "In6.Cu")
		(net "M_C_CPU1_SA_DQ<14>")
	)
	(segment
		(start 83.342988 -271.964658)
		(end 82.564478 -271.964658)
		(width 0.18288)
		(layer "In6.Cu")
		(net "M_C_CPU1_SA_DQ<14>")
	)
	(segment
		(start 38.237414 -298.393612)
		(end 38.237414 -299.098716)
		(width 0.18288)
		(layer "In6.Cu")
		(net "M_C_CPU1_SA_DQ<14>")
	)
	(segment
		(start 40.453818 -292.945312)
		(end 40.453818 -293.203884)
		(width 0.18288)
		(layer "In6.Cu")
		(net "M_C_CPU1_SA_DQ<14>")
	)
	(segment
		(start 95.597218 -268.900402)
		(end 95.571564 -268.885416)
		(width 0.088646)
		(layer "In6.Cu")
		(net "M_C_CPU1_SA_DQ<14>")
	)
	(segment
		(start 46.416722 -290.391596)
		(end 46.110906 -290.697412)
		(width 0.18288)
		(layer "In6.Cu")
		(net "M_C_CPU1_SA_DQ<14>")
	)
	(segment
		(start 43.706034 -292.193726)
		(end 42.751756 -292.193726)
		(width 0.18288)
		(layer "In6.Cu")
		(net "M_C_CPU1_SA_DQ<14>")
	)
	(segment
		(start 38.237414 -297.011852)
		(end 38.237414 -297.336972)
		(width 0.18288)
		(layer "In6.Cu")
		(net "M_C_CPU1_SA_DQ<14>")
	)
	(segment
		(start 59.740546 -284.695646)
		(end 59.011566 -285.424626)
		(width 0.18288)
		(layer "In6.Cu")
		(net "M_C_CPU1_SA_DQ<14>")
	)
	(segment
		(start 45.103796 -290.391596)
		(end 44.953428 -290.241228)
		(width 0.18288)
		(layer "In6.Cu")
		(net "M_C_CPU1_SA_DQ<14>")
	)
	(segment
		(start 54.796436 -288.023808)
		(end 54.161944 -288.023808)
		(width 0.18288)
		(layer "In6.Cu")
		(net "M_C_CPU1_SA_DQ<14>")
	)
	(segment
		(start 85.43798 -269.98168)
		(end 84.993988 -270.425672)
		(width 0.088646)
		(layer "In6.Cu")
		(net "M_C_CPU1_SA_DQ<14>")
	)
	(segment
		(start 39.001446 -296.320972)
		(end 39.001446 -296.646092)
		(width 0.18288)
		(layer "In6.Cu")
		(net "M_C_CPU1_SA_DQ<14>")
	)
	(segment
		(start 97.183194 -269.38351)
		(end 96.624902 -268.951964)
		(width 0.088646)
		(layer "In6.Cu")
		(net "M_C_CPU1_SA_DQ<14>")
	)
	(segment
		(start 85.791802 -269.98168)
		(end 85.43798 -269.98168)
		(width 0.088646)
		(layer "In6.Cu")
		(net "M_C_CPU1_SA_DQ<14>")
	)
	(segment
		(start 63.844424 -283.418788)
		(end 62.567566 -284.695646)
		(width 0.18288)
		(layer "In6.Cu")
		(net "M_C_CPU1_SA_DQ<14>")
	)
	(segment
		(start 38.237414 -294.856154)
		(end 38.237414 -295.955212)
		(width 0.18288)
		(layer "In6.Cu")
		(net "M_C_CPU1_SA_DQ<14>")
	)
	(segment
		(start 62.567566 -284.695646)
		(end 59.740546 -284.695646)
		(width 0.18288)
		(layer "In6.Cu")
		(net "M_C_CPU1_SA_DQ<14>")
	)
	(segment
		(start 38.237414 -299.098716)
		(end 37.75964 -299.57649)
		(width 0.18288)
		(layer "In6.Cu")
		(net "M_C_CPU1_SA_DQ<14>")
	)
	(segment
		(start 45.723302 -290.697412)
		(end 45.417486 -290.391596)
		(width 0.18288)
		(layer "In6.Cu")
		(net "M_C_CPU1_SA_DQ<14>")
	)
	(segment
		(start 52.644294 -289.541458)
		(end 49.963832 -289.541458)
		(width 0.18288)
		(layer "In6.Cu")
		(net "M_C_CPU1_SA_DQ<14>")
	)
	(segment
		(start 49.963832 -289.541458)
		(end 49.113694 -290.391596)
		(width 0.18288)
		(layer "In6.Cu")
		(net "M_C_CPU1_SA_DQ<14>")
	)
	(segment
		(start 42.083736 -291.5539)
		(end 41.891458 -291.746178)
		(width 0.18288)
		(layer "In6.Cu")
		(net "M_C_CPU1_SA_DQ<14>")
	)
	(segment
		(start 40.453818 -293.203884)
		(end 40.595042 -293.345108)
		(width 0.18288)
		(layer "In6.Cu")
		(net "M_C_CPU1_SA_DQ<14>")
	)
	(segment
		(start 40.595042 -293.345108)
		(end 40.595042 -293.603426)
		(width 0.18288)
		(layer "In6.Cu")
		(net "M_C_CPU1_SA_DQ<14>")
	)
	(segment
		(start 41.891458 -291.746178)
		(end 41.891458 -292.30701)
		(width 0.18288)
		(layer "In6.Cu")
		(net "M_C_CPU1_SA_DQ<14>")
	)
	(segment
		(start 38.420294 -296.828972)
		(end 38.237414 -297.011852)
		(width 0.18288)
		(layer "In6.Cu")
		(net "M_C_CPU1_SA_DQ<14>")
	)
	(segment
		(start 40.683942 -292.715188)
		(end 40.453818 -292.945312)
		(width 0.18288)
		(layer "In6.Cu")
		(net "M_C_CPU1_SA_DQ<14>")
	)
	(segment
		(start 40.942514 -292.715188)
		(end 40.683942 -292.715188)
		(width 0.18288)
		(layer "In6.Cu")
		(net "M_C_CPU1_SA_DQ<14>")
	)
	(segment
		(start 90.332306 -268.887956)
		(end 90.321892 -268.894052)
		(width 0.088646)
		(layer "In6.Cu")
		(net "M_C_CPU1_SA_DQ<14>")
	)
	(segment
		(start 83.57616 -271.964658)
		(end 83.342988 -271.964658)
		(width 0.088646)
		(layer "In6.Cu")
		(net "M_C_CPU1_SA_DQ<14>")
	)
	(segment
		(start 58.226706 -285.424626)
		(end 56.520588 -287.130744)
		(width 0.18288)
		(layer "In6.Cu")
		(net "M_C_CPU1_SA_DQ<14>")
	)
	(segment
		(start 44.34967 -291.55009)
		(end 43.706034 -292.193726)
		(width 0.18288)
		(layer "In6.Cu")
		(net "M_C_CPU1_SA_DQ<14>")
	)
	(segment
		(start 84.993988 -270.425672)
		(end 84.733638 -270.425672)
		(width 0.088646)
		(layer "In6.Cu")
		(net "M_C_CPU1_SA_DQ<14>")
	)
	(segment
		(start 39.001446 -298.027852)
		(end 38.818566 -298.210732)
		(width 0.18288)
		(layer "In6.Cu")
		(net "M_C_CPU1_SA_DQ<14>")
	)
	(segment
		(start 65.031112 -283.418788)
		(end 63.844424 -283.418788)
		(width 0.18288)
		(layer "In6.Cu")
		(net "M_C_CPU1_SA_DQ<14>")
	)
	(segment
		(start 56.520588 -287.130744)
		(end 55.6895 -287.130744)
		(width 0.18288)
		(layer "In6.Cu")
		(net "M_C_CPU1_SA_DQ<14>")
	)
	(segment
		(start 40.105584 -294.092884)
		(end 39.000684 -294.092884)
		(width 0.18288)
		(layer "In6.Cu")
		(net "M_C_CPU1_SA_DQ<14>")
	)
	(segment
		(start 40.595042 -293.603426)
		(end 40.105584 -294.092884)
		(width 0.18288)
		(layer "In6.Cu")
		(net "M_C_CPU1_SA_DQ<14>")
	)
	(segment
		(start 36.56711 -299.57649)
		(end 35.976814 -300.166786)
		(width 0.18288)
		(layer "In6.Cu")
		(net "M_C_CPU1_SA_DQ<14>")
	)
	(segment
		(start 67.10299 -282.880562)
		(end 65.569338 -282.880562)
		(width 0.18288)
		(layer "In6.Cu")
		(net "M_C_CPU1_SA_DQ<14>")
	)
	(segment
		(start 83.84667 -271.694148)
		(end 83.57616 -271.964658)
		(width 0.088646)
		(layer "In6.Cu")
		(net "M_C_CPU1_SA_DQ<14>")
	)
	(segment
		(start 92.216478 -268.885416)
		(end 92.201746 -268.894052)
		(width 0.088646)
		(layer "In6.Cu")
		(net "M_C_CPU1_SA_DQ<14>")
	)
	(segment
		(start 94.09176 -268.887956)
		(end 94.081346 -268.894052)
		(width 0.088646)
		(layer "In6.Cu")
		(net "M_C_CPU1_SA_DQ<14>")
	)
	(segment
		(start 45.417486 -290.391596)
		(end 45.103796 -290.391596)
		(width 0.18288)
		(layer "In6.Cu")
		(net "M_C_CPU1_SA_DQ<14>")
	)
	(segment
		(start 38.237414 -297.336972)
		(end 38.420294 -297.519852)
		(width 0.18288)
		(layer "In6.Cu")
		(net "M_C_CPU1_SA_DQ<14>")
	)
	(segment
		(start 42.591736 -292.033706)
		(end 42.591736 -291.71392)
		(width 0.18288)
		(layer "In6.Cu")
		(net "M_C_CPU1_SA_DQ<14>")
	)
	(segment
		(start 48.02124 -290.697412)
		(end 47.715424 -290.391596)
		(width 0.18288)
		(layer "In6.Cu")
		(net "M_C_CPU1_SA_DQ<14>")
	)
	(segment
		(start 38.420294 -297.519852)
		(end 38.818566 -297.519852)
		(width 0.18288)
		(layer "In6.Cu")
		(net "M_C_CPU1_SA_DQ<14>")
	)
	(segment
		(start 42.751756 -292.193726)
		(end 42.591736 -292.033706)
		(width 0.18288)
		(layer "In6.Cu")
		(net "M_C_CPU1_SA_DQ<14>")
	)
	(segment
		(start 46.110906 -290.697412)
		(end 45.723302 -290.697412)
		(width 0.18288)
		(layer "In6.Cu")
		(net "M_C_CPU1_SA_DQ<14>")
	)
	(segment
		(start 74.804524 -275.179028)
		(end 67.10299 -282.880562)
		(width 0.18288)
		(layer "In6.Cu")
		(net "M_C_CPU1_SA_DQ<14>")
	)
	(segment
		(start 44.953428 -290.241228)
		(end 44.704 -290.241228)
		(width 0.18288)
		(layer "In6.Cu")
		(net "M_C_CPU1_SA_DQ<14>")
	)
	(segment
		(start 37.75964 -299.57649)
		(end 36.56711 -299.57649)
		(width 0.18288)
		(layer "In6.Cu")
		(net "M_C_CPU1_SA_DQ<14>")
	)
	(segment
		(start 38.420294 -296.138092)
		(end 38.818566 -296.138092)
		(width 0.18288)
		(layer "In6.Cu")
		(net "M_C_CPU1_SA_DQ<14>")
	)
	(segment
		(start 54.161944 -288.023808)
		(end 52.644294 -289.541458)
		(width 0.18288)
		(layer "In6.Cu")
		(net "M_C_CPU1_SA_DQ<14>")
	)
	(segment
		(start 38.818566 -296.138092)
		(end 39.001446 -296.320972)
		(width 0.18288)
		(layer "In6.Cu")
		(net "M_C_CPU1_SA_DQ<14>")
	)
	(segment
		(start 44.34967 -291.298122)
		(end 44.34967 -291.55009)
		(width 0.18288)
		(layer "In6.Cu")
		(net "M_C_CPU1_SA_DQ<14>")
	)
	(arc
		(start 86.101682 -269.702788)
		(mid 86.035358 -269.745868)
		(end 85.975698 -269.797784)
		(width 0.088646)
		(layer "In6.Cu")
		(net "M_C_CPU1_SA_DQ<14>")
	)
	(arc
		(start 93.141546 -268.894052)
		(mid 92.954348 -268.944195)
		(end 92.76715 -268.894052)
		(width 0.088646)
		(layer "In6.Cu")
		(net "M_C_CPU1_SA_DQ<14>")
	)
	(arc
		(start 88.442292 -268.894052)
		(mid 88.255094 -268.944195)
		(end 88.067896 -268.894052)
		(width 0.088646)
		(layer "In6.Cu")
		(net "M_C_CPU1_SA_DQ<14>")
	)
	(arc
		(start 89.007696 -268.894052)
		(mid 88.724994 -268.818276)
		(end 88.442292 -268.894052)
		(width 0.088646)
		(layer "In6.Cu")
		(net "M_C_CPU1_SA_DQ<14>")
	)
	(arc
		(start 91.82735 -268.894052)
		(mid 91.544648 -268.818276)
		(end 91.261946 -268.894052)
		(width 0.088646)
		(layer "In6.Cu")
		(net "M_C_CPU1_SA_DQ<14>")
	)
	(arc
		(start 95.972884 -268.901672)
		(mid 95.784887 -268.951661)
		(end 95.597218 -268.900402)
		(width 0.088646)
		(layer "In6.Cu")
		(net "M_C_CPU1_SA_DQ<14>")
	)
	(arc
		(start 90.321892 -268.894052)
		(mid 90.134694 -268.944195)
		(end 89.947496 -268.894052)
		(width 0.088646)
		(layer "In6.Cu")
		(net "M_C_CPU1_SA_DQ<14>")
	)
	(arc
		(start 89.947496 -268.894052)
		(mid 89.664794 -268.818276)
		(end 89.382092 -268.894052)
		(width 0.088646)
		(layer "In6.Cu")
		(net "M_C_CPU1_SA_DQ<14>")
	)
	(arc
		(start 92.201746 -268.894052)
		(mid 92.014548 -268.944195)
		(end 91.82735 -268.894052)
		(width 0.088646)
		(layer "In6.Cu")
		(net "M_C_CPU1_SA_DQ<14>")
	)
	(arc
		(start 94.646496 -268.894052)
		(mid 94.369937 -268.818309)
		(end 94.09176 -268.887956)
		(width 0.088646)
		(layer "In6.Cu")
		(net "M_C_CPU1_SA_DQ<14>")
	)
	(arc
		(start 95.020892 -268.894052)
		(mid 94.833694 -268.944195)
		(end 94.646496 -268.894052)
		(width 0.088646)
		(layer "In6.Cu")
		(net "M_C_CPU1_SA_DQ<14>")
	)
	(arc
		(start 87.128096 -268.894052)
		(mid 86.845394 -268.818276)
		(end 86.562692 -268.894052)
		(width 0.088646)
		(layer "In6.Cu")
		(net "M_C_CPU1_SA_DQ<14>")
	)
	(arc
		(start 90.88755 -268.894052)
		(mid 90.610737 -268.818182)
		(end 90.332306 -268.887956)
		(width 0.088646)
		(layer "In6.Cu")
		(net "M_C_CPU1_SA_DQ<14>")
	)
	(arc
		(start 87.502492 -268.894052)
		(mid 87.315294 -268.944195)
		(end 87.128096 -268.894052)
		(width 0.088646)
		(layer "In6.Cu")
		(net "M_C_CPU1_SA_DQ<14>")
	)
	(arc
		(start 91.261946 -268.894052)
		(mid 91.074748 -268.944195)
		(end 90.88755 -268.894052)
		(width 0.088646)
		(layer "In6.Cu")
		(net "M_C_CPU1_SA_DQ<14>")
	)
	(arc
		(start 86.280244 -269.38351)
		(mid 86.232565 -269.56641)
		(end 86.101682 -269.702788)
		(width 0.088646)
		(layer "In6.Cu")
		(net "M_C_CPU1_SA_DQ<14>")
	)
	(arc
		(start 86.562692 -268.894052)
		(mid 86.358357 -269.096657)
		(end 86.280244 -269.373604)
		(width 0.088646)
		(layer "In6.Cu")
		(net "M_C_CPU1_SA_DQ<14>")
	)
	(arc
		(start 92.76715 -268.894052)
		(mid 92.492951 -268.818217)
		(end 92.216478 -268.885416)
		(width 0.088646)
		(layer "In6.Cu")
		(net "M_C_CPU1_SA_DQ<14>")
	)
	(arc
		(start 89.382092 -268.894052)
		(mid 89.194894 -268.944195)
		(end 89.007696 -268.894052)
		(width 0.088646)
		(layer "In6.Cu")
		(net "M_C_CPU1_SA_DQ<14>")
	)
	(arc
		(start 95.571564 -268.885416)
		(mid 95.295089 -268.818096)
		(end 95.020892 -268.894052)
		(width 0.088646)
		(layer "In6.Cu")
		(net "M_C_CPU1_SA_DQ<14>")
	)
	(arc
		(start 94.081346 -268.894052)
		(mid 93.894148 -268.944195)
		(end 93.70695 -268.894052)
		(width 0.088646)
		(layer "In6.Cu")
		(net "M_C_CPU1_SA_DQ<14>")
	)
	(arc
		(start 96.541844 -268.903196)
		(mid 96.257575 -268.825683)
		(end 95.972884 -268.901672)
		(width 0.088646)
		(layer "In6.Cu")
		(net "M_C_CPU1_SA_DQ<14>")
	)
	(arc
		(start 93.70695 -268.894052)
		(mid 93.432751 -268.818217)
		(end 93.156278 -268.885416)
		(width 0.088646)
		(layer "In6.Cu")
		(net "M_C_CPU1_SA_DQ<14>")
	)
	(arc
		(start 88.067896 -268.894052)
		(mid 87.785194 -268.818276)
		(end 87.502492 -268.894052)
		(width 0.088646)
		(layer "In6.Cu")
		(net "M_C_CPU1_SA_DQ<14>")
	)
	(segment
		(start 24.562308 -299.316648)
		(end 24.773636 -299.527976)
		(width 0.20066)
		(layer "F.Cu")
		(net "M_C_CPU1_SA_DQ<13>")
	)
	(segment
		(start 23.228046 -299.316648)
		(end 24.562308 -299.316648)
		(width 0.20066)
		(layer "F.Cu")
		(net "M_C_CPU1_SA_DQ<13>")
	)
	(segment
		(start 25.432512 -299.373544)
		(end 25.432512 -299.045376)
		(width 0.20066)
		(layer "F.Cu")
		(net "M_C_CPU1_SA_DQ<13>")
	)
	(segment
		(start 95.773494 -268.033754)
		(end 95.773748 -268.034008)
		(width 0.20066)
		(layer "F.Cu")
		(net "M_C_CPU1_SA_DQ<13>")
	)
	(segment
		(start 24.773636 -299.527976)
		(end 25.27808 -299.527976)
		(width 0.20066)
		(layer "F.Cu")
		(net "M_C_CPU1_SA_DQ<13>")
	)
	(segment
		(start 28.707588 -298.891706)
		(end 29.13253 -299.316648)
		(width 0.20066)
		(layer "F.Cu")
		(net "M_C_CPU1_SA_DQ<13>")
	)
	(segment
		(start 31.876746 -299.316648)
		(end 30.771846 -299.316648)
		(width 0.20066)
		(layer "F.Cu")
		(net "M_C_CPU1_SA_DQ<13>")
	)
	(segment
		(start 25.432512 -299.045376)
		(end 25.595072 -298.882816)
		(width 0.20066)
		(layer "F.Cu")
		(net "M_C_CPU1_SA_DQ<13>")
	)
	(segment
		(start 28.529026 -298.891706)
		(end 28.707588 -298.891706)
		(width 0.20066)
		(layer "F.Cu")
		(net "M_C_CPU1_SA_DQ<13>")
	)
	(segment
		(start 26.20391 -298.882816)
		(end 26.2128 -298.891706)
		(width 0.1016)
		(layer "F.Cu")
		(net "M_C_CPU1_SA_DQ<13>")
	)
	(segment
		(start 95.773748 -268.034008)
		(end 95.773748 -268.569694)
		(width 0.20066)
		(layer "F.Cu")
		(net "M_C_CPU1_SA_DQ<13>")
	)
	(segment
		(start 29.13253 -299.316648)
		(end 30.771846 -299.316648)
		(width 0.20066)
		(layer "F.Cu")
		(net "M_C_CPU1_SA_DQ<13>")
	)
	(segment
		(start 26.2128 -298.891706)
		(end 28.198318 -298.891706)
		(width 0.1016)
		(layer "F.Cu")
		(net "M_C_CPU1_SA_DQ<13>")
	)
	(segment
		(start 25.27808 -299.527976)
		(end 25.432512 -299.373544)
		(width 0.20066)
		(layer "F.Cu")
		(net "M_C_CPU1_SA_DQ<13>")
	)
	(segment
		(start 25.595072 -298.882816)
		(end 26.20391 -298.882816)
		(width 0.20066)
		(layer "F.Cu")
		(net "M_C_CPU1_SA_DQ<13>")
	)
	(segment
		(start 28.198318 -298.891706)
		(end 28.529026 -298.891706)
		(width 0.101854)
		(layer "F.Cu")
		(net "M_C_CPU1_SA_DQ<13>")
	)
	(segment
		(start 63.641986 -282.910026)
		(end 62.397386 -284.154626)
		(width 0.18288)
		(layer "In6.Cu")
		(net "M_C_CPU1_SA_DQ<13>")
	)
	(segment
		(start 33.175702 -298.287694)
		(end 33.175702 -298.708572)
		(width 0.18288)
		(layer "In6.Cu")
		(net "M_C_CPU1_SA_DQ<13>")
	)
	(segment
		(start 33.175702 -298.708572)
		(end 32.992822 -298.891452)
		(width 0.18288)
		(layer "In6.Cu")
		(net "M_C_CPU1_SA_DQ<13>")
	)
	(segment
		(start 93.156278 -268.253972)
		(end 93.141546 -268.245336)
		(width 0.088646)
		(layer "In6.Cu")
		(net "M_C_CPU1_SA_DQ<13>")
	)
	(segment
		(start 90.88755 -268.245336)
		(end 90.877136 -268.251432)
		(width 0.088646)
		(layer "In6.Cu")
		(net "M_C_CPU1_SA_DQ<13>")
	)
	(segment
		(start 35.778694 -298.891452)
		(end 34.049462 -298.891452)
		(width 0.18288)
		(layer "In6.Cu")
		(net "M_C_CPU1_SA_DQ<13>")
	)
	(segment
		(start 33.866582 -298.287694)
		(end 33.683702 -298.104814)
		(width 0.18288)
		(layer "In6.Cu")
		(net "M_C_CPU1_SA_DQ<13>")
	)
	(segment
		(start 67.464432 -281.75585)
		(end 66.22796 -281.75585)
		(width 0.18288)
		(layer "In6.Cu")
		(net "M_C_CPU1_SA_DQ<13>")
	)
	(segment
		(start 85.640418 -269.118334)
		(end 85.196426 -269.562326)
		(width 0.088646)
		(layer "In6.Cu")
		(net "M_C_CPU1_SA_DQ<13>")
	)
	(segment
		(start 48.985678 -289.541712)
		(end 44.621704 -289.541712)
		(width 0.18288)
		(layer "In6.Cu")
		(net "M_C_CPU1_SA_DQ<13>")
	)
	(segment
		(start 33.358582 -298.104814)
		(end 33.175702 -298.287694)
		(width 0.18288)
		(layer "In6.Cu")
		(net "M_C_CPU1_SA_DQ<13>")
	)
	(segment
		(start 58.534554 -284.154626)
		(end 56.672226 -286.016954)
		(width 0.18288)
		(layer "In6.Cu")
		(net "M_C_CPU1_SA_DQ<13>")
	)
	(segment
		(start 74.423524 -274.796758)
		(end 67.464432 -281.75585)
		(width 0.18288)
		(layer "In6.Cu")
		(net "M_C_CPU1_SA_DQ<13>")
	)
	(segment
		(start 35.778948 -298.891706)
		(end 35.778694 -298.891452)
		(width 0.18288)
		(layer "In6.Cu")
		(net "M_C_CPU1_SA_DQ<13>")
	)
	(segment
		(start 54.78653 -286.857948)
		(end 54.32679 -286.857948)
		(width 0.18288)
		(layer "In6.Cu")
		(net "M_C_CPU1_SA_DQ<13>")
	)
	(segment
		(start 64.936116 -282.37942)
		(end 64.40551 -282.910026)
		(width 0.18288)
		(layer "In6.Cu")
		(net "M_C_CPU1_SA_DQ<13>")
	)
	(segment
		(start 95.969836 -268.250416)
		(end 95.960946 -268.245336)
		(width 0.088646)
		(layer "In6.Cu")
		(net "M_C_CPU1_SA_DQ<13>")
	)
	(segment
		(start 40.31234 -291.860224)
		(end 40.31234 -292.34384)
		(width 0.18288)
		(layer "In6.Cu")
		(net "M_C_CPU1_SA_DQ<13>")
	)
	(segment
		(start 84.602574 -269.562326)
		(end 84.38769 -269.77721)
		(width 0.088646)
		(layer "In6.Cu")
		(net "M_C_CPU1_SA_DQ<13>")
	)
	(segment
		(start 64.40551 -282.910026)
		(end 63.641986 -282.910026)
		(width 0.18288)
		(layer "In6.Cu")
		(net "M_C_CPU1_SA_DQ<13>")
	)
	(segment
		(start 85.196426 -269.562326)
		(end 84.602574 -269.562326)
		(width 0.088646)
		(layer "In6.Cu")
		(net "M_C_CPU1_SA_DQ<13>")
	)
	(segment
		(start 91.276678 -268.253972)
		(end 91.261946 -268.245336)
		(width 0.088646)
		(layer "In6.Cu")
		(net "M_C_CPU1_SA_DQ<13>")
	)
	(segment
		(start 41.160446 -291.012118)
		(end 40.31234 -291.860224)
		(width 0.18288)
		(layer "In6.Cu")
		(net "M_C_CPU1_SA_DQ<13>")
	)
	(segment
		(start 52.493164 -288.691574)
		(end 49.835816 -288.691574)
		(width 0.18288)
		(layer "In6.Cu")
		(net "M_C_CPU1_SA_DQ<13>")
	)
	(segment
		(start 83.342988 -271.435068)
		(end 82.541872 -271.435068)
		(width 0.18288)
		(layer "In6.Cu")
		(net "M_C_CPU1_SA_DQ<13>")
	)
	(segment
		(start 49.835816 -288.691574)
		(end 48.985678 -289.541712)
		(width 0.18288)
		(layer "In6.Cu")
		(net "M_C_CPU1_SA_DQ<13>")
	)
	(segment
		(start 94.09176 -268.251432)
		(end 94.081346 -268.245336)
		(width 0.088646)
		(layer "In6.Cu")
		(net "M_C_CPU1_SA_DQ<13>")
	)
	(segment
		(start 37.66439 -298.708572)
		(end 37.48151 -298.891452)
		(width 0.18288)
		(layer "In6.Cu")
		(net "M_C_CPU1_SA_DQ<13>")
	)
	(segment
		(start 39.039038 -293.14267)
		(end 37.66439 -294.517318)
		(width 0.18288)
		(layer "In6.Cu")
		(net "M_C_CPU1_SA_DQ<13>")
	)
	(segment
		(start 83.555078 -271.435068)
		(end 83.342988 -271.435068)
		(width 0.088646)
		(layer "In6.Cu")
		(net "M_C_CPU1_SA_DQ<13>")
	)
	(segment
		(start 86.000844 -268.569694)
		(end 86.000844 -268.5796)
		(width 0.088646)
		(layer "In6.Cu")
		(net "M_C_CPU1_SA_DQ<13>")
	)
	(segment
		(start 92.216478 -268.253972)
		(end 92.201746 -268.245336)
		(width 0.088646)
		(layer "In6.Cu")
		(net "M_C_CPU1_SA_DQ<13>")
	)
	(segment
		(start 36.256976 -298.891706)
		(end 35.778948 -298.891706)
		(width 0.18288)
		(layer "In6.Cu")
		(net "M_C_CPU1_SA_DQ<13>")
	)
	(segment
		(start 56.672226 -286.016954)
		(end 55.627524 -286.016954)
		(width 0.18288)
		(layer "In6.Cu")
		(net "M_C_CPU1_SA_DQ<13>")
	)
	(segment
		(start 95.031306 -268.251432)
		(end 95.020892 -268.245336)
		(width 0.088646)
		(layer "In6.Cu")
		(net "M_C_CPU1_SA_DQ<13>")
	)
	(segment
		(start 96.086422 -268.569694)
		(end 96.143826 -268.51229)
		(width 0.088646)
		(layer "In6.Cu")
		(net "M_C_CPU1_SA_DQ<13>")
	)
	(segment
		(start 83.643724 -271.20596)
		(end 83.643724 -271.346422)
		(width 0.088646)
		(layer "In6.Cu")
		(net "M_C_CPU1_SA_DQ<13>")
	)
	(segment
		(start 62.397386 -284.154626)
		(end 58.534554 -284.154626)
		(width 0.18288)
		(layer "In6.Cu")
		(net "M_C_CPU1_SA_DQ<13>")
	)
	(segment
		(start 84.38769 -269.77721)
		(end 84.38769 -270.461994)
		(width 0.088646)
		(layer "In6.Cu")
		(net "M_C_CPU1_SA_DQ<13>")
	)
	(segment
		(start 44.621704 -289.541712)
		(end 43.151298 -291.012118)
		(width 0.18288)
		(layer "In6.Cu")
		(net "M_C_CPU1_SA_DQ<13>")
	)
	(segment
		(start 66.22796 -281.75585)
		(end 65.60439 -282.37942)
		(width 0.18288)
		(layer "In6.Cu")
		(net "M_C_CPU1_SA_DQ<13>")
	)
	(segment
		(start 37.48151 -298.891452)
		(end 36.25723 -298.891452)
		(width 0.18288)
		(layer "In6.Cu")
		(net "M_C_CPU1_SA_DQ<13>")
	)
	(segment
		(start 32.301942 -298.891452)
		(end 31.876746 -299.316648)
		(width 0.18288)
		(layer "In6.Cu")
		(net "M_C_CPU1_SA_DQ<13>")
	)
	(segment
		(start 84.38769 -270.461994)
		(end 83.643724 -271.20596)
		(width 0.088646)
		(layer "In6.Cu")
		(net "M_C_CPU1_SA_DQ<13>")
	)
	(segment
		(start 55.627524 -286.016954)
		(end 54.78653 -286.857948)
		(width 0.18288)
		(layer "In6.Cu")
		(net "M_C_CPU1_SA_DQ<13>")
	)
	(segment
		(start 33.683702 -298.104814)
		(end 33.358582 -298.104814)
		(width 0.18288)
		(layer "In6.Cu")
		(net "M_C_CPU1_SA_DQ<13>")
	)
	(segment
		(start 86.188296 -268.245336)
		(end 86.179406 -268.250416)
		(width 0.088646)
		(layer "In6.Cu")
		(net "M_C_CPU1_SA_DQ<13>")
	)
	(segment
		(start 65.60439 -282.37942)
		(end 64.936116 -282.37942)
		(width 0.18288)
		(layer "In6.Cu")
		(net "M_C_CPU1_SA_DQ<13>")
	)
	(segment
		(start 32.992822 -298.891452)
		(end 32.301942 -298.891452)
		(width 0.18288)
		(layer "In6.Cu")
		(net "M_C_CPU1_SA_DQ<13>")
	)
	(segment
		(start 39.51351 -293.14267)
		(end 39.039038 -293.14267)
		(width 0.18288)
		(layer "In6.Cu")
		(net "M_C_CPU1_SA_DQ<13>")
	)
	(segment
		(start 33.866582 -298.708572)
		(end 33.866582 -298.287694)
		(width 0.18288)
		(layer "In6.Cu")
		(net "M_C_CPU1_SA_DQ<13>")
	)
	(segment
		(start 83.643724 -271.346422)
		(end 83.555078 -271.435068)
		(width 0.088646)
		(layer "In6.Cu")
		(net "M_C_CPU1_SA_DQ<13>")
	)
	(segment
		(start 54.32679 -286.857948)
		(end 52.493164 -288.691574)
		(width 0.18288)
		(layer "In6.Cu")
		(net "M_C_CPU1_SA_DQ<13>")
	)
	(segment
		(start 36.25723 -298.891452)
		(end 36.256976 -298.891706)
		(width 0.18288)
		(layer "In6.Cu")
		(net "M_C_CPU1_SA_DQ<13>")
	)
	(segment
		(start 37.66439 -294.517318)
		(end 37.66439 -298.708572)
		(width 0.18288)
		(layer "In6.Cu")
		(net "M_C_CPU1_SA_DQ<13>")
	)
	(segment
		(start 43.151298 -291.012118)
		(end 41.160446 -291.012118)
		(width 0.18288)
		(layer "In6.Cu")
		(net "M_C_CPU1_SA_DQ<13>")
	)
	(segment
		(start 40.31234 -292.34384)
		(end 39.51351 -293.14267)
		(width 0.18288)
		(layer "In6.Cu")
		(net "M_C_CPU1_SA_DQ<13>")
	)
	(segment
		(start 82.541872 -271.435068)
		(end 74.423524 -274.796758)
		(width 0.18288)
		(layer "In6.Cu")
		(net "M_C_CPU1_SA_DQ<13>")
	)
	(segment
		(start 95.773748 -268.569694)
		(end 96.086422 -268.569694)
		(width 0.088646)
		(layer "In6.Cu")
		(net "M_C_CPU1_SA_DQ<13>")
	)
	(segment
		(start 34.049462 -298.891452)
		(end 33.866582 -298.708572)
		(width 0.18288)
		(layer "In6.Cu")
		(net "M_C_CPU1_SA_DQ<13>")
	)
	(arc
		(start 96.143826 -268.51229)
		(mid 96.08567 -268.362177)
		(end 95.969836 -268.250416)
		(width 0.088646)
		(layer "In6.Cu")
		(net "M_C_CPU1_SA_DQ<13>")
	)
	(arc
		(start 93.70695 -268.245336)
		(mid 93.432751 -268.321171)
		(end 93.156278 -268.253972)
		(width 0.088646)
		(layer "In6.Cu")
		(net "M_C_CPU1_SA_DQ<13>")
	)
	(arc
		(start 88.067896 -268.245336)
		(mid 87.785194 -268.321112)
		(end 87.502492 -268.245336)
		(width 0.088646)
		(layer "In6.Cu")
		(net "M_C_CPU1_SA_DQ<13>")
	)
	(arc
		(start 94.081346 -268.245336)
		(mid 93.894148 -268.195193)
		(end 93.70695 -268.245336)
		(width 0.088646)
		(layer "In6.Cu")
		(net "M_C_CPU1_SA_DQ<13>")
	)
	(arc
		(start 89.382092 -268.245336)
		(mid 89.194894 -268.195193)
		(end 89.007696 -268.245336)
		(width 0.088646)
		(layer "In6.Cu")
		(net "M_C_CPU1_SA_DQ<13>")
	)
	(arc
		(start 88.442292 -268.245336)
		(mid 88.255094 -268.195193)
		(end 88.067896 -268.245336)
		(width 0.088646)
		(layer "In6.Cu")
		(net "M_C_CPU1_SA_DQ<13>")
	)
	(arc
		(start 86.562692 -268.245336)
		(mid 86.375494 -268.195193)
		(end 86.188296 -268.245336)
		(width 0.088646)
		(layer "In6.Cu")
		(net "M_C_CPU1_SA_DQ<13>")
	)
	(arc
		(start 95.58655 -268.245336)
		(mid 95.309737 -268.321206)
		(end 95.031306 -268.251432)
		(width 0.088646)
		(layer "In6.Cu")
		(net "M_C_CPU1_SA_DQ<13>")
	)
	(arc
		(start 91.261946 -268.245336)
		(mid 91.074748 -268.195193)
		(end 90.88755 -268.245336)
		(width 0.088646)
		(layer "In6.Cu")
		(net "M_C_CPU1_SA_DQ<13>")
	)
	(arc
		(start 85.718396 -269.059152)
		(mid 85.677466 -269.086185)
		(end 85.640418 -269.118334)
		(width 0.088646)
		(layer "In6.Cu")
		(net "M_C_CPU1_SA_DQ<13>")
	)
	(arc
		(start 95.020892 -268.245336)
		(mid 94.833694 -268.195193)
		(end 94.646496 -268.245336)
		(width 0.088646)
		(layer "In6.Cu")
		(net "M_C_CPU1_SA_DQ<13>")
	)
	(arc
		(start 86.179406 -268.250416)
		(mid 86.048492 -268.386776)
		(end 86.000844 -268.569694)
		(width 0.088646)
		(layer "In6.Cu")
		(net "M_C_CPU1_SA_DQ<13>")
	)
	(arc
		(start 94.646496 -268.245336)
		(mid 94.369937 -268.321079)
		(end 94.09176 -268.251432)
		(width 0.088646)
		(layer "In6.Cu")
		(net "M_C_CPU1_SA_DQ<13>")
	)
	(arc
		(start 93.141546 -268.245336)
		(mid 92.954348 -268.195193)
		(end 92.76715 -268.245336)
		(width 0.088646)
		(layer "In6.Cu")
		(net "M_C_CPU1_SA_DQ<13>")
	)
	(arc
		(start 91.82735 -268.245336)
		(mid 91.553151 -268.321171)
		(end 91.276678 -268.253972)
		(width 0.088646)
		(layer "In6.Cu")
		(net "M_C_CPU1_SA_DQ<13>")
	)
	(arc
		(start 90.877136 -268.251432)
		(mid 90.598704 -268.321278)
		(end 90.321892 -268.245336)
		(width 0.088646)
		(layer "In6.Cu")
		(net "M_C_CPU1_SA_DQ<13>")
	)
	(arc
		(start 87.128096 -268.245336)
		(mid 86.845394 -268.321112)
		(end 86.562692 -268.245336)
		(width 0.088646)
		(layer "In6.Cu")
		(net "M_C_CPU1_SA_DQ<13>")
	)
	(arc
		(start 89.947496 -268.245336)
		(mid 89.664794 -268.321112)
		(end 89.382092 -268.245336)
		(width 0.088646)
		(layer "In6.Cu")
		(net "M_C_CPU1_SA_DQ<13>")
	)
	(arc
		(start 87.502492 -268.245336)
		(mid 87.315294 -268.195193)
		(end 87.128096 -268.245336)
		(width 0.088646)
		(layer "In6.Cu")
		(net "M_C_CPU1_SA_DQ<13>")
	)
	(arc
		(start 95.960946 -268.245336)
		(mid 95.773748 -268.195193)
		(end 95.58655 -268.245336)
		(width 0.088646)
		(layer "In6.Cu")
		(net "M_C_CPU1_SA_DQ<13>")
	)
	(arc
		(start 92.76715 -268.245336)
		(mid 92.492951 -268.321171)
		(end 92.216478 -268.253972)
		(width 0.088646)
		(layer "In6.Cu")
		(net "M_C_CPU1_SA_DQ<13>")
	)
	(arc
		(start 89.007696 -268.245336)
		(mid 88.724994 -268.321112)
		(end 88.442292 -268.245336)
		(width 0.088646)
		(layer "In6.Cu")
		(net "M_C_CPU1_SA_DQ<13>")
	)
	(arc
		(start 92.201746 -268.245336)
		(mid 92.014548 -268.195193)
		(end 91.82735 -268.245336)
		(width 0.088646)
		(layer "In6.Cu")
		(net "M_C_CPU1_SA_DQ<13>")
	)
	(arc
		(start 86.000844 -268.5796)
		(mid 85.922733 -268.856549)
		(end 85.718396 -269.059152)
		(width 0.088646)
		(layer "In6.Cu")
		(net "M_C_CPU1_SA_DQ<13>")
	)
	(arc
		(start 90.321892 -268.245336)
		(mid 90.134694 -268.195193)
		(end 89.947496 -268.245336)
		(width 0.088646)
		(layer "In6.Cu")
		(net "M_C_CPU1_SA_DQ<13>")
	)
	(segment
		(start 31.876746 -301.01667)
		(end 30.771846 -301.01667)
		(width 0.20066)
		(layer "F.Cu")
		(net "M_C_CPU1_SA_DQ<12>")
	)
	(segment
		(start 26.459942 -300.591728)
		(end 28.529026 -300.591728)
		(width 0.1016)
		(layer "F.Cu")
		(net "M_C_CPU1_SA_DQ<12>")
	)
	(segment
		(start 23.228046 -301.01667)
		(end 24.562308 -301.01667)
		(width 0.20066)
		(layer "F.Cu")
		(net "M_C_CPU1_SA_DQ<12>")
	)
	(segment
		(start 29.402786 -301.01667)
		(end 30.771846 -301.01667)
		(width 0.20066)
		(layer "F.Cu")
		(net "M_C_CPU1_SA_DQ<12>")
	)
	(segment
		(start 24.562308 -301.01667)
		(end 24.801068 -301.25543)
		(width 0.20066)
		(layer "F.Cu")
		(net "M_C_CPU1_SA_DQ<12>")
	)
	(segment
		(start 26.212038 -300.591728)
		(end 26.459942 -300.591728)
		(width 0.101854)
		(layer "F.Cu")
		(net "M_C_CPU1_SA_DQ<12>")
	)
	(segment
		(start 95.303594 -268.847824)
		(end 95.303594 -269.38351)
		(width 0.20066)
		(layer "F.Cu")
		(net "M_C_CPU1_SA_DQ<12>")
	)
	(segment
		(start 95.303848 -268.84757)
		(end 95.303594 -268.847824)
		(width 0.20066)
		(layer "F.Cu")
		(net "M_C_CPU1_SA_DQ<12>")
	)
	(segment
		(start 28.977844 -300.591728)
		(end 29.402786 -301.01667)
		(width 0.20066)
		(layer "F.Cu")
		(net "M_C_CPU1_SA_DQ<12>")
	)
	(segment
		(start 28.529026 -300.591728)
		(end 28.977844 -300.591728)
		(width 0.20066)
		(layer "F.Cu")
		(net "M_C_CPU1_SA_DQ<12>")
	)
	(segment
		(start 26.20391 -300.5836)
		(end 26.212038 -300.591728)
		(width 0.101854)
		(layer "F.Cu")
		(net "M_C_CPU1_SA_DQ<12>")
	)
	(segment
		(start 25.432512 -300.79315)
		(end 25.642062 -300.5836)
		(width 0.20066)
		(layer "F.Cu")
		(net "M_C_CPU1_SA_DQ<12>")
	)
	(segment
		(start 25.432512 -301.08271)
		(end 25.432512 -300.79315)
		(width 0.20066)
		(layer "F.Cu")
		(net "M_C_CPU1_SA_DQ<12>")
	)
	(segment
		(start 25.259792 -301.25543)
		(end 25.432512 -301.08271)
		(width 0.20066)
		(layer "F.Cu")
		(net "M_C_CPU1_SA_DQ<12>")
	)
	(segment
		(start 25.642062 -300.5836)
		(end 26.20391 -300.5836)
		(width 0.20066)
		(layer "F.Cu")
		(net "M_C_CPU1_SA_DQ<12>")
	)
	(segment
		(start 24.801068 -301.25543)
		(end 25.259792 -301.25543)
		(width 0.20066)
		(layer "F.Cu")
		(net "M_C_CPU1_SA_DQ<12>")
	)
	(segment
		(start 94.176596 -269.059152)
		(end 94.161864 -269.067788)
		(width 0.088646)
		(layer "In6.Cu")
		(net "M_C_CPU1_SA_DQ<12>")
	)
	(segment
		(start 33.866328 -300.408848)
		(end 33.866328 -299.929042)
		(width 0.18288)
		(layer "In6.Cu")
		(net "M_C_CPU1_SA_DQ<12>")
	)
	(segment
		(start 35.248088 -299.929042)
		(end 35.065208 -299.746162)
		(width 0.18288)
		(layer "In6.Cu")
		(net "M_C_CPU1_SA_DQ<12>")
	)
	(segment
		(start 34.557208 -299.929042)
		(end 34.557208 -300.408848)
		(width 0.18288)
		(layer "In6.Cu")
		(net "M_C_CPU1_SA_DQ<12>")
	)
	(segment
		(start 82.57032 -272.50136)
		(end 75.140312 -275.579078)
		(width 0.18288)
		(layer "In6.Cu")
		(net "M_C_CPU1_SA_DQ<12>")
	)
	(segment
		(start 49.896268 -290.391596)
		(end 49.045876 -291.241988)
		(width 0.18288)
		(layer "In6.Cu")
		(net "M_C_CPU1_SA_DQ<12>")
	)
	(segment
		(start 33.683448 -299.746162)
		(end 33.358328 -299.746162)
		(width 0.18288)
		(layer "In6.Cu")
		(net "M_C_CPU1_SA_DQ<12>")
	)
	(segment
		(start 86.658196 -269.059152)
		(end 86.649306 -269.064232)
		(width 0.088646)
		(layer "In6.Cu")
		(net "M_C_CPU1_SA_DQ<12>")
	)
	(segment
		(start 54.327552 -288.5694)
		(end 52.505356 -290.391596)
		(width 0.18288)
		(layer "In6.Cu")
		(net "M_C_CPU1_SA_DQ<12>")
	)
	(segment
		(start 92.296996 -269.059152)
		(end 92.286582 -269.065248)
		(width 0.088646)
		(layer "In6.Cu")
		(net "M_C_CPU1_SA_DQ<12>")
	)
	(segment
		(start 35.065208 -299.746162)
		(end 34.740088 -299.746162)
		(width 0.18288)
		(layer "In6.Cu")
		(net "M_C_CPU1_SA_DQ<12>")
	)
	(segment
		(start 61.846714 -285.233364)
		(end 61.123068 -285.95701)
		(width 0.18288)
		(layer "In6.Cu")
		(net "M_C_CPU1_SA_DQ<12>")
	)
	(segment
		(start 93.236796 -269.059152)
		(end 93.222064 -269.067788)
		(width 0.088646)
		(layer "In6.Cu")
		(net "M_C_CPU1_SA_DQ<12>")
	)
	(segment
		(start 33.175448 -299.929042)
		(end 33.175448 -300.408848)
		(width 0.18288)
		(layer "In6.Cu")
		(net "M_C_CPU1_SA_DQ<12>")
	)
	(segment
		(start 84.044282 -271.97685)
		(end 83.519772 -272.50136)
		(width 0.088646)
		(layer "In6.Cu")
		(net "M_C_CPU1_SA_DQ<12>")
	)
	(segment
		(start 94.9325 -269.282672)
		(end 94.550992 -269.059152)
		(width 0.088646)
		(layer "In6.Cu")
		(net "M_C_CPU1_SA_DQ<12>")
	)
	(segment
		(start 49.045876 -291.241988)
		(end 45.368464 -291.241988)
		(width 0.18288)
		(layer "In6.Cu")
		(net "M_C_CPU1_SA_DQ<12>")
	)
	(segment
		(start 59.30519 -286.145732)
		(end 59.117484 -285.958026)
		(width 0.18288)
		(layer "In6.Cu")
		(net "M_C_CPU1_SA_DQ<12>")
	)
	(segment
		(start 64.0207 -283.946854)
		(end 62.73419 -285.233364)
		(width 0.18288)
		(layer "In6.Cu")
		(net "M_C_CPU1_SA_DQ<12>")
	)
	(segment
		(start 85.516974 -270.171926)
		(end 85.070188 -270.618712)
		(width 0.088646)
		(layer "In6.Cu")
		(net "M_C_CPU1_SA_DQ<12>")
	)
	(segment
		(start 84.81822 -270.618712)
		(end 84.044282 -271.39265)
		(width 0.088646)
		(layer "In6.Cu")
		(net "M_C_CPU1_SA_DQ<12>")
	)
	(segment
		(start 38.282372 -300.591728)
		(end 35.430968 -300.591728)
		(width 0.18288)
		(layer "In6.Cu")
		(net "M_C_CPU1_SA_DQ<12>")
	)
	(segment
		(start 32.301688 -300.591728)
		(end 31.876746 -301.01667)
		(width 0.18288)
		(layer "In6.Cu")
		(net "M_C_CPU1_SA_DQ<12>")
	)
	(segment
		(start 83.519772 -272.50136)
		(end 83.342988 -272.50136)
		(width 0.088646)
		(layer "In6.Cu")
		(net "M_C_CPU1_SA_DQ<12>")
	)
	(segment
		(start 42.18813 -292.720014)
		(end 39.904416 -295.003728)
		(width 0.18288)
		(layer "In6.Cu")
		(net "M_C_CPU1_SA_DQ<12>")
	)
	(segment
		(start 32.992568 -300.591728)
		(end 32.301688 -300.591728)
		(width 0.18288)
		(layer "In6.Cu")
		(net "M_C_CPU1_SA_DQ<12>")
	)
	(segment
		(start 60.054744 -285.95701)
		(end 59.95035 -286.061404)
		(width 0.18288)
		(layer "In6.Cu")
		(net "M_C_CPU1_SA_DQ<12>")
	)
	(segment
		(start 95.303594 -269.38351)
		(end 94.9325 -269.282672)
		(width 0.088646)
		(layer "In6.Cu")
		(net "M_C_CPU1_SA_DQ<12>")
	)
	(segment
		(start 34.740088 -299.746162)
		(end 34.557208 -299.929042)
		(width 0.18288)
		(layer "In6.Cu")
		(net "M_C_CPU1_SA_DQ<12>")
	)
	(segment
		(start 35.430968 -300.591728)
		(end 35.248088 -300.408848)
		(width 0.18288)
		(layer "In6.Cu")
		(net "M_C_CPU1_SA_DQ<12>")
	)
	(segment
		(start 55.962296 -287.651698)
		(end 55.044594 -288.5694)
		(width 0.18288)
		(layer "In6.Cu")
		(net "M_C_CPU1_SA_DQ<12>")
	)
	(segment
		(start 33.866328 -299.929042)
		(end 33.683448 -299.746162)
		(width 0.18288)
		(layer "In6.Cu")
		(net "M_C_CPU1_SA_DQ<12>")
	)
	(segment
		(start 83.342988 -272.50136)
		(end 82.57032 -272.50136)
		(width 0.18288)
		(layer "In6.Cu")
		(net "M_C_CPU1_SA_DQ<12>")
	)
	(segment
		(start 85.870796 -270.171926)
		(end 85.516974 -270.171926)
		(width 0.088646)
		(layer "In6.Cu")
		(net "M_C_CPU1_SA_DQ<12>")
	)
	(segment
		(start 86.470744 -269.38351)
		(end 86.470744 -269.402052)
		(width 0.088646)
		(layer "In6.Cu")
		(net "M_C_CPU1_SA_DQ<12>")
	)
	(segment
		(start 55.044594 -288.5694)
		(end 54.327552 -288.5694)
		(width 0.18288)
		(layer "In6.Cu")
		(net "M_C_CPU1_SA_DQ<12>")
	)
	(segment
		(start 65.781174 -283.378656)
		(end 65.212976 -283.946854)
		(width 0.18288)
		(layer "In6.Cu")
		(net "M_C_CPU1_SA_DQ<12>")
	)
	(segment
		(start 62.73419 -285.233364)
		(end 61.846714 -285.233364)
		(width 0.18288)
		(layer "In6.Cu")
		(net "M_C_CPU1_SA_DQ<12>")
	)
	(segment
		(start 56.867806 -287.651698)
		(end 55.962296 -287.651698)
		(width 0.18288)
		(layer "In6.Cu")
		(net "M_C_CPU1_SA_DQ<12>")
	)
	(segment
		(start 75.140312 -275.579078)
		(end 67.340734 -283.378656)
		(width 0.18288)
		(layer "In6.Cu")
		(net "M_C_CPU1_SA_DQ<12>")
	)
	(segment
		(start 34.049208 -300.591728)
		(end 33.866328 -300.408848)
		(width 0.18288)
		(layer "In6.Cu")
		(net "M_C_CPU1_SA_DQ<12>")
	)
	(segment
		(start 52.505356 -290.391596)
		(end 49.896268 -290.391596)
		(width 0.18288)
		(layer "In6.Cu")
		(net "M_C_CPU1_SA_DQ<12>")
	)
	(segment
		(start 59.95035 -286.061404)
		(end 59.746642 -286.145732)
		(width 0.18288)
		(layer "In6.Cu")
		(net "M_C_CPU1_SA_DQ<12>")
	)
	(segment
		(start 59.117484 -285.958026)
		(end 58.561478 -285.958026)
		(width 0.18288)
		(layer "In6.Cu")
		(net "M_C_CPU1_SA_DQ<12>")
	)
	(segment
		(start 45.368464 -291.241988)
		(end 43.890438 -292.720014)
		(width 0.18288)
		(layer "In6.Cu")
		(net "M_C_CPU1_SA_DQ<12>")
	)
	(segment
		(start 33.175448 -300.408848)
		(end 32.992568 -300.591728)
		(width 0.18288)
		(layer "In6.Cu")
		(net "M_C_CPU1_SA_DQ<12>")
	)
	(segment
		(start 59.746642 -286.145732)
		(end 59.30519 -286.145732)
		(width 0.18288)
		(layer "In6.Cu")
		(net "M_C_CPU1_SA_DQ<12>")
	)
	(segment
		(start 33.358328 -299.746162)
		(end 33.175448 -299.929042)
		(width 0.18288)
		(layer "In6.Cu")
		(net "M_C_CPU1_SA_DQ<12>")
	)
	(segment
		(start 35.248088 -300.408848)
		(end 35.248088 -299.929042)
		(width 0.18288)
		(layer "In6.Cu")
		(net "M_C_CPU1_SA_DQ<12>")
	)
	(segment
		(start 86.110318 -269.932404)
		(end 85.870796 -270.171926)
		(width 0.088646)
		(layer "In6.Cu")
		(net "M_C_CPU1_SA_DQ<12>")
	)
	(segment
		(start 84.044282 -271.39265)
		(end 84.044282 -271.97685)
		(width 0.088646)
		(layer "In6.Cu")
		(net "M_C_CPU1_SA_DQ<12>")
	)
	(segment
		(start 91.35745 -269.059152)
		(end 91.347036 -269.065248)
		(width 0.088646)
		(layer "In6.Cu")
		(net "M_C_CPU1_SA_DQ<12>")
	)
	(segment
		(start 85.070188 -270.618712)
		(end 84.81822 -270.618712)
		(width 0.088646)
		(layer "In6.Cu")
		(net "M_C_CPU1_SA_DQ<12>")
	)
	(segment
		(start 58.561478 -285.958026)
		(end 56.867806 -287.651698)
		(width 0.18288)
		(layer "In6.Cu")
		(net "M_C_CPU1_SA_DQ<12>")
	)
	(segment
		(start 65.212976 -283.946854)
		(end 64.0207 -283.946854)
		(width 0.18288)
		(layer "In6.Cu")
		(net "M_C_CPU1_SA_DQ<12>")
	)
	(segment
		(start 34.374328 -300.591728)
		(end 34.049208 -300.591728)
		(width 0.18288)
		(layer "In6.Cu")
		(net "M_C_CPU1_SA_DQ<12>")
	)
	(segment
		(start 67.340734 -283.378656)
		(end 65.781174 -283.378656)
		(width 0.18288)
		(layer "In6.Cu")
		(net "M_C_CPU1_SA_DQ<12>")
	)
	(segment
		(start 34.557208 -300.408848)
		(end 34.374328 -300.591728)
		(width 0.18288)
		(layer "In6.Cu")
		(net "M_C_CPU1_SA_DQ<12>")
	)
	(segment
		(start 43.890438 -292.720014)
		(end 42.18813 -292.720014)
		(width 0.18288)
		(layer "In6.Cu")
		(net "M_C_CPU1_SA_DQ<12>")
	)
	(segment
		(start 39.904416 -295.003728)
		(end 39.904416 -298.969684)
		(width 0.18288)
		(layer "In6.Cu")
		(net "M_C_CPU1_SA_DQ<12>")
	)
	(segment
		(start 39.904416 -298.969684)
		(end 38.282372 -300.591728)
		(width 0.18288)
		(layer "In6.Cu")
		(net "M_C_CPU1_SA_DQ<12>")
	)
	(segment
		(start 61.123068 -285.95701)
		(end 60.054744 -285.95701)
		(width 0.18288)
		(layer "In6.Cu")
		(net "M_C_CPU1_SA_DQ<12>")
	)
	(arc
		(start 88.537796 -269.059152)
		(mid 88.255094 -269.134928)
		(end 87.972392 -269.059152)
		(width 0.088646)
		(layer "In6.Cu")
		(net "M_C_CPU1_SA_DQ<12>")
	)
	(arc
		(start 92.286582 -269.065248)
		(mid 92.008404 -269.134971)
		(end 91.731846 -269.059152)
		(width 0.088646)
		(layer "In6.Cu")
		(net "M_C_CPU1_SA_DQ<12>")
	)
	(arc
		(start 86.188296 -269.873222)
		(mid 86.147366 -269.900255)
		(end 86.110318 -269.932404)
		(width 0.088646)
		(layer "In6.Cu")
		(net "M_C_CPU1_SA_DQ<12>")
	)
	(arc
		(start 87.032592 -269.059152)
		(mid 86.845394 -269.009009)
		(end 86.658196 -269.059152)
		(width 0.088646)
		(layer "In6.Cu")
		(net "M_C_CPU1_SA_DQ<12>")
	)
	(arc
		(start 91.731846 -269.059152)
		(mid 91.544648 -269.009009)
		(end 91.35745 -269.059152)
		(width 0.088646)
		(layer "In6.Cu")
		(net "M_C_CPU1_SA_DQ<12>")
	)
	(arc
		(start 87.972392 -269.059152)
		(mid 87.785194 -269.009009)
		(end 87.597996 -269.059152)
		(width 0.088646)
		(layer "In6.Cu")
		(net "M_C_CPU1_SA_DQ<12>")
	)
	(arc
		(start 93.611192 -269.059152)
		(mid 93.423994 -269.009009)
		(end 93.236796 -269.059152)
		(width 0.088646)
		(layer "In6.Cu")
		(net "M_C_CPU1_SA_DQ<12>")
	)
	(arc
		(start 94.161864 -269.067788)
		(mid 93.885389 -269.135108)
		(end 93.611192 -269.059152)
		(width 0.088646)
		(layer "In6.Cu")
		(net "M_C_CPU1_SA_DQ<12>")
	)
	(arc
		(start 94.550992 -269.059152)
		(mid 94.363794 -269.009009)
		(end 94.176596 -269.059152)
		(width 0.088646)
		(layer "In6.Cu")
		(net "M_C_CPU1_SA_DQ<12>")
	)
	(arc
		(start 86.470744 -269.402052)
		(mid 86.390582 -269.674241)
		(end 86.188296 -269.873222)
		(width 0.088646)
		(layer "In6.Cu")
		(net "M_C_CPU1_SA_DQ<12>")
	)
	(arc
		(start 89.477596 -269.059152)
		(mid 89.194894 -269.134928)
		(end 88.912192 -269.059152)
		(width 0.088646)
		(layer "In6.Cu")
		(net "M_C_CPU1_SA_DQ<12>")
	)
	(arc
		(start 86.649306 -269.064232)
		(mid 86.518392 -269.200592)
		(end 86.470744 -269.38351)
		(width 0.088646)
		(layer "In6.Cu")
		(net "M_C_CPU1_SA_DQ<12>")
	)
	(arc
		(start 87.597996 -269.059152)
		(mid 87.315294 -269.134928)
		(end 87.032592 -269.059152)
		(width 0.088646)
		(layer "In6.Cu")
		(net "M_C_CPU1_SA_DQ<12>")
	)
	(arc
		(start 90.791792 -269.059152)
		(mid 90.604594 -269.009009)
		(end 90.417396 -269.059152)
		(width 0.088646)
		(layer "In6.Cu")
		(net "M_C_CPU1_SA_DQ<12>")
	)
	(arc
		(start 93.222064 -269.067788)
		(mid 92.945589 -269.135108)
		(end 92.671392 -269.059152)
		(width 0.088646)
		(layer "In6.Cu")
		(net "M_C_CPU1_SA_DQ<12>")
	)
	(arc
		(start 90.417396 -269.059152)
		(mid 90.134694 -269.134928)
		(end 89.851992 -269.059152)
		(width 0.088646)
		(layer "In6.Cu")
		(net "M_C_CPU1_SA_DQ<12>")
	)
	(arc
		(start 92.671392 -269.059152)
		(mid 92.484194 -269.009009)
		(end 92.296996 -269.059152)
		(width 0.088646)
		(layer "In6.Cu")
		(net "M_C_CPU1_SA_DQ<12>")
	)
	(arc
		(start 89.851992 -269.059152)
		(mid 89.664794 -269.009009)
		(end 89.477596 -269.059152)
		(width 0.088646)
		(layer "In6.Cu")
		(net "M_C_CPU1_SA_DQ<12>")
	)
	(arc
		(start 91.347036 -269.065248)
		(mid 91.068604 -269.135094)
		(end 90.791792 -269.059152)
		(width 0.088646)
		(layer "In6.Cu")
		(net "M_C_CPU1_SA_DQ<12>")
	)
	(arc
		(start 88.912192 -269.059152)
		(mid 88.724994 -269.009009)
		(end 88.537796 -269.059152)
		(width 0.088646)
		(layer "In6.Cu")
		(net "M_C_CPU1_SA_DQ<12>")
	)
	(segment
		(start 29.025342 -304.416714)
		(end 29.151326 -304.542698)
		(width 0.20066)
		(layer "F.Cu")
		(net "M_C_CPU1_SA_DQ<11>")
	)
	(segment
		(start 29.29382 -304.85588)
		(end 29.647642 -304.85588)
		(width 0.20066)
		(layer "F.Cu")
		(net "M_C_CPU1_SA_DQ<11>")
	)
	(segment
		(start 35.976814 -304.416714)
		(end 34.871914 -304.416714)
		(width 0.20066)
		(layer "F.Cu")
		(net "M_C_CPU1_SA_DQ<11>")
	)
	(segment
		(start 32.666178 -304.692558)
		(end 32.666178 -304.54092)
		(width 0.20066)
		(layer "F.Cu")
		(net "M_C_CPU1_SA_DQ<11>")
	)
	(segment
		(start 32.794702 -304.412396)
		(end 33.189926 -304.412396)
		(width 0.20066)
		(layer "F.Cu")
		(net "M_C_CPU1_SA_DQ<11>")
	)
	(segment
		(start 27.328114 -304.416714)
		(end 29.025342 -304.416714)
		(width 0.20066)
		(layer "F.Cu")
		(net "M_C_CPU1_SA_DQ<11>")
	)
	(segment
		(start 29.899864 -304.841656)
		(end 31.972758 -304.841656)
		(width 0.1016)
		(layer "F.Cu")
		(net "M_C_CPU1_SA_DQ<11>")
	)
	(segment
		(start 33.189926 -304.412396)
		(end 33.401762 -304.624232)
		(width 0.20066)
		(layer "F.Cu")
		(net "M_C_CPU1_SA_DQ<11>")
	)
	(segment
		(start 29.661866 -304.841656)
		(end 29.899864 -304.841656)
		(width 0.101854)
		(layer "F.Cu")
		(net "M_C_CPU1_SA_DQ<11>")
	)
	(segment
		(start 29.151326 -304.713386)
		(end 29.29382 -304.85588)
		(width 0.20066)
		(layer "F.Cu")
		(net "M_C_CPU1_SA_DQ<11>")
	)
	(segment
		(start 32.51708 -304.841656)
		(end 32.666178 -304.692558)
		(width 0.20066)
		(layer "F.Cu")
		(net "M_C_CPU1_SA_DQ<11>")
	)
	(segment
		(start 29.151326 -304.542698)
		(end 29.151326 -304.713386)
		(width 0.20066)
		(layer "F.Cu")
		(net "M_C_CPU1_SA_DQ<11>")
	)
	(segment
		(start 31.972758 -304.841656)
		(end 32.51708 -304.841656)
		(width 0.20066)
		(layer "F.Cu")
		(net "M_C_CPU1_SA_DQ<11>")
	)
	(segment
		(start 33.401762 -304.624232)
		(end 33.848294 -304.624232)
		(width 0.20066)
		(layer "F.Cu")
		(net "M_C_CPU1_SA_DQ<11>")
	)
	(segment
		(start 32.666178 -304.54092)
		(end 32.794702 -304.412396)
		(width 0.20066)
		(layer "F.Cu")
		(net "M_C_CPU1_SA_DQ<11>")
	)
	(segment
		(start 33.848294 -304.624232)
		(end 34.055812 -304.416714)
		(width 0.20066)
		(layer "F.Cu")
		(net "M_C_CPU1_SA_DQ<11>")
	)
	(segment
		(start 29.647642 -304.85588)
		(end 29.661866 -304.841656)
		(width 0.101854)
		(layer "F.Cu")
		(net "M_C_CPU1_SA_DQ<11>")
	)
	(segment
		(start 34.055812 -304.416714)
		(end 34.871914 -304.416714)
		(width 0.20066)
		(layer "F.Cu")
		(net "M_C_CPU1_SA_DQ<11>")
	)
	(arc
		(start 97.183448 -270.475456)
		(mid 97.183384 -270.743426)
		(end 97.183194 -271.011396)
		(width 0.20066)
		(layer "F.Cu")
		(net "M_C_CPU1_SA_DQ<11>")
	)
	(segment
		(start 86.280244 -272.625058)
		(end 86.280244 -272.639282)
		(width 0.088646)
		(layer "In6.Cu")
		(net "M_C_CPU1_SA_DQ<11>")
	)
	(segment
		(start 52.963318 -294.044624)
		(end 52.733194 -294.274748)
		(width 0.18288)
		(layer "In6.Cu")
		(net "M_C_CPU1_SA_DQ<11>")
	)
	(segment
		(start 52.944014 -295.002458)
		(end 52.454556 -295.491916)
		(width 0.18288)
		(layer "In6.Cu")
		(net "M_C_CPU1_SA_DQ<11>")
	)
	(segment
		(start 37.379148 -304.884582)
		(end 36.444682 -304.884582)
		(width 0.18288)
		(layer "In6.Cu")
		(net "M_C_CPU1_SA_DQ<11>")
	)
	(segment
		(start 86.101682 -272.95856)
		(end 86.092792 -272.96364)
		(width 0.088646)
		(layer "In6.Cu")
		(net "M_C_CPU1_SA_DQ<11>")
	)
	(segment
		(start 61.4426 -289.84702)
		(end 61.25972 -289.66414)
		(width 0.18288)
		(layer "In6.Cu")
		(net "M_C_CPU1_SA_DQ<11>")
	)
	(segment
		(start 83.902042 -274.719034)
		(end 83.342988 -274.719034)
		(width 0.088646)
		(layer "In6.Cu")
		(net "M_C_CPU1_SA_DQ<11>")
	)
	(segment
		(start 58.201052 -290.528756)
		(end 56.228996 -292.500812)
		(width 0.18288)
		(layer "In6.Cu")
		(net "M_C_CPU1_SA_DQ<11>")
	)
	(segment
		(start 93.236796 -271.335754)
		(end 93.222064 -271.327118)
		(width 0.088646)
		(layer "In6.Cu")
		(net "M_C_CPU1_SA_DQ<11>")
	)
	(segment
		(start 36.444682 -304.884582)
		(end 35.976814 -304.416714)
		(width 0.18288)
		(layer "In6.Cu")
		(net "M_C_CPU1_SA_DQ<11>")
	)
	(segment
		(start 53.710586 -293.297356)
		(end 53.710586 -293.555928)
		(width 0.18288)
		(layer "In6.Cu")
		(net "M_C_CPU1_SA_DQ<11>")
	)
	(segment
		(start 92.296996 -271.335754)
		(end 92.282264 -271.327118)
		(width 0.088646)
		(layer "In6.Cu")
		(net "M_C_CPU1_SA_DQ<11>")
	)
	(segment
		(start 83.342988 -274.719034)
		(end 82.790792 -274.719034)
		(width 0.18288)
		(layer "In6.Cu")
		(net "M_C_CPU1_SA_DQ<11>")
	)
	(segment
		(start 84.967572 -273.653504)
		(end 83.902042 -274.719034)
		(width 0.088646)
		(layer "In6.Cu")
		(net "M_C_CPU1_SA_DQ<11>")
	)
	(segment
		(start 84.967572 -273.21891)
		(end 84.967572 -273.653504)
		(width 0.088646)
		(layer "In6.Cu")
		(net "M_C_CPU1_SA_DQ<11>")
	)
	(segment
		(start 43.051476 -301.256446)
		(end 42.092626 -302.215296)
		(width 0.18288)
		(layer "In6.Cu")
		(net "M_C_CPU1_SA_DQ<11>")
	)
	(segment
		(start 61.25972 -289.241484)
		(end 61.07684 -289.058604)
		(width 0.18288)
		(layer "In6.Cu")
		(net "M_C_CPU1_SA_DQ<11>")
	)
	(segment
		(start 38.60292 -303.66081)
		(end 37.379148 -304.884582)
		(width 0.18288)
		(layer "In6.Cu")
		(net "M_C_CPU1_SA_DQ<11>")
	)
	(segment
		(start 94.856554 -270.939006)
		(end 94.828106 -271.00784)
		(width 0.088646)
		(layer "In6.Cu")
		(net "M_C_CPU1_SA_DQ<11>")
	)
	(segment
		(start 52.733194 -294.53332)
		(end 52.944014 -294.74414)
		(width 0.18288)
		(layer "In6.Cu")
		(net "M_C_CPU1_SA_DQ<11>")
	)
	(segment
		(start 52.733194 -294.274748)
		(end 52.733194 -294.53332)
		(width 0.18288)
		(layer "In6.Cu")
		(net "M_C_CPU1_SA_DQ<11>")
	)
	(segment
		(start 48.585882 -295.491916)
		(end 47.735998 -296.3418)
		(width 0.18288)
		(layer "In6.Cu")
		(net "M_C_CPU1_SA_DQ<11>")
	)
	(segment
		(start 65.707006 -287.418526)
		(end 63.278512 -289.84702)
		(width 0.18288)
		(layer "In6.Cu")
		(net "M_C_CPU1_SA_DQ<11>")
	)
	(segment
		(start 95.496888 -270.69034)
		(end 95.485204 -270.683736)
		(width 0.088646)
		(layer "In6.Cu")
		(net "M_C_CPU1_SA_DQ<11>")
	)
	(segment
		(start 94.762574 -271.166082)
		(end 94.730824 -271.198086)
		(width 0.088646)
		(layer "In6.Cu")
		(net "M_C_CPU1_SA_DQ<11>")
	)
	(segment
		(start 54.668674 -293.277798)
		(end 54.410102 -293.277798)
		(width 0.18288)
		(layer "In6.Cu")
		(net "M_C_CPU1_SA_DQ<11>")
	)
	(segment
		(start 46.016418 -296.3418)
		(end 45.677328 -296.00271)
		(width 0.18288)
		(layer "In6.Cu")
		(net "M_C_CPU1_SA_DQ<11>")
	)
	(segment
		(start 53.22189 -294.044624)
		(end 52.963318 -294.044624)
		(width 0.18288)
		(layer "In6.Cu")
		(net "M_C_CPU1_SA_DQ<11>")
	)
	(segment
		(start 85.718396 -272.96364)
		(end 85.707982 -272.957544)
		(width 0.088646)
		(layer "In6.Cu")
		(net "M_C_CPU1_SA_DQ<11>")
	)
	(segment
		(start 87.128096 -272.14957)
		(end 87.113364 -272.140934)
		(width 0.088646)
		(layer "In6.Cu")
		(net "M_C_CPU1_SA_DQ<11>")
	)
	(segment
		(start 60.75172 -289.058604)
		(end 60.56884 -289.241484)
		(width 0.18288)
		(layer "In6.Cu")
		(net "M_C_CPU1_SA_DQ<11>")
	)
	(segment
		(start 58.957464 -290.528756)
		(end 58.201052 -290.528756)
		(width 0.18288)
		(layer "In6.Cu")
		(net "M_C_CPU1_SA_DQ<11>")
	)
	(segment
		(start 94.17685 -271.335754)
		(end 94.166436 -271.329658)
		(width 0.088646)
		(layer "In6.Cu")
		(net "M_C_CPU1_SA_DQ<11>")
	)
	(segment
		(start 61.07684 -289.058604)
		(end 60.75172 -289.058604)
		(width 0.18288)
		(layer "In6.Cu")
		(net "M_C_CPU1_SA_DQ<11>")
	)
	(segment
		(start 43.051476 -297.33494)
		(end 43.051476 -301.256446)
		(width 0.18288)
		(layer "In6.Cu")
		(net "M_C_CPU1_SA_DQ<11>")
	)
	(segment
		(start 82.790792 -274.719034)
		(end 78.014576 -276.69744)
		(width 0.18288)
		(layer "In6.Cu")
		(net "M_C_CPU1_SA_DQ<11>")
	)
	(segment
		(start 87.511382 -272.14449)
		(end 87.502492 -272.14957)
		(width 0.088646)
		(layer "In6.Cu")
		(net "M_C_CPU1_SA_DQ<11>")
	)
	(segment
		(start 44.383706 -296.00271)
		(end 43.051476 -297.33494)
		(width 0.18288)
		(layer "In6.Cu")
		(net "M_C_CPU1_SA_DQ<11>")
	)
	(segment
		(start 78.014576 -276.69744)
		(end 67.29349 -287.418526)
		(width 0.18288)
		(layer "In6.Cu")
		(net "M_C_CPU1_SA_DQ<11>")
	)
	(segment
		(start 53.921406 -294.025066)
		(end 53.691282 -294.25519)
		(width 0.18288)
		(layer "In6.Cu")
		(net "M_C_CPU1_SA_DQ<11>")
	)
	(segment
		(start 89.477596 -271.335754)
		(end 89.462864 -271.327118)
		(width 0.088646)
		(layer "In6.Cu")
		(net "M_C_CPU1_SA_DQ<11>")
	)
	(segment
		(start 63.278512 -289.84702)
		(end 61.4426 -289.84702)
		(width 0.18288)
		(layer "In6.Cu")
		(net "M_C_CPU1_SA_DQ<11>")
	)
	(segment
		(start 60.56884 -289.66414)
		(end 60.38596 -289.84702)
		(width 0.18288)
		(layer "In6.Cu")
		(net "M_C_CPU1_SA_DQ<11>")
	)
	(segment
		(start 96.84893 -270.923512)
		(end 96.425004 -270.683736)
		(width 0.088646)
		(layer "In6.Cu")
		(net "M_C_CPU1_SA_DQ<11>")
	)
	(segment
		(start 59.6392 -289.84702)
		(end 58.957464 -290.528756)
		(width 0.18288)
		(layer "In6.Cu")
		(net "M_C_CPU1_SA_DQ<11>")
	)
	(segment
		(start 53.94071 -293.067232)
		(end 53.710586 -293.297356)
		(width 0.18288)
		(layer "In6.Cu")
		(net "M_C_CPU1_SA_DQ<11>")
	)
	(segment
		(start 53.710586 -293.555928)
		(end 53.921406 -293.766748)
		(width 0.18288)
		(layer "In6.Cu")
		(net "M_C_CPU1_SA_DQ<11>")
	)
	(segment
		(start 52.454556 -295.491916)
		(end 48.585882 -295.491916)
		(width 0.18288)
		(layer "In6.Cu")
		(net "M_C_CPU1_SA_DQ<11>")
	)
	(segment
		(start 94.551754 -271.3355)
		(end 94.551246 -271.335754)
		(width 0.088646)
		(layer "In6.Cu")
		(net "M_C_CPU1_SA_DQ<11>")
	)
	(segment
		(start 42.092626 -302.215296)
		(end 38.60292 -303.66081)
		(width 0.18288)
		(layer "In6.Cu")
		(net "M_C_CPU1_SA_DQ<11>")
	)
	(segment
		(start 47.735998 -296.3418)
		(end 46.016418 -296.3418)
		(width 0.18288)
		(layer "In6.Cu")
		(net "M_C_CPU1_SA_DQ<11>")
	)
	(segment
		(start 53.691282 -294.25519)
		(end 53.43271 -294.25519)
		(width 0.18288)
		(layer "In6.Cu")
		(net "M_C_CPU1_SA_DQ<11>")
	)
	(segment
		(start 56.228996 -292.500812)
		(end 55.44566 -292.500812)
		(width 0.18288)
		(layer "In6.Cu")
		(net "M_C_CPU1_SA_DQ<11>")
	)
	(segment
		(start 45.677328 -296.00271)
		(end 44.383706 -296.00271)
		(width 0.18288)
		(layer "In6.Cu")
		(net "M_C_CPU1_SA_DQ<11>")
	)
	(segment
		(start 85.036152 -273.053302)
		(end 84.967572 -273.21891)
		(width 0.088646)
		(layer "In6.Cu")
		(net "M_C_CPU1_SA_DQ<11>")
	)
	(segment
		(start 55.44566 -292.500812)
		(end 54.668674 -293.277798)
		(width 0.18288)
		(layer "In6.Cu")
		(net "M_C_CPU1_SA_DQ<11>")
	)
	(segment
		(start 54.199282 -293.067232)
		(end 53.94071 -293.067232)
		(width 0.18288)
		(layer "In6.Cu")
		(net "M_C_CPU1_SA_DQ<11>")
	)
	(segment
		(start 67.29349 -287.418526)
		(end 65.707006 -287.418526)
		(width 0.18288)
		(layer "In6.Cu")
		(net "M_C_CPU1_SA_DQ<11>")
	)
	(segment
		(start 61.25972 -289.66414)
		(end 61.25972 -289.241484)
		(width 0.18288)
		(layer "In6.Cu")
		(net "M_C_CPU1_SA_DQ<11>")
	)
	(segment
		(start 87.689944 -271.815306)
		(end 87.689944 -271.825212)
		(width 0.088646)
		(layer "In6.Cu")
		(net "M_C_CPU1_SA_DQ<11>")
	)
	(segment
		(start 54.410102 -293.277798)
		(end 54.199282 -293.067232)
		(width 0.18288)
		(layer "In6.Cu")
		(net "M_C_CPU1_SA_DQ<11>")
	)
	(segment
		(start 60.56884 -289.241484)
		(end 60.56884 -289.66414)
		(width 0.18288)
		(layer "In6.Cu")
		(net "M_C_CPU1_SA_DQ<11>")
	)
	(segment
		(start 53.43271 -294.25519)
		(end 53.22189 -294.044624)
		(width 0.18288)
		(layer "In6.Cu")
		(net "M_C_CPU1_SA_DQ<11>")
	)
	(segment
		(start 52.944014 -294.74414)
		(end 52.944014 -295.002458)
		(width 0.18288)
		(layer "In6.Cu")
		(net "M_C_CPU1_SA_DQ<11>")
	)
	(segment
		(start 60.38596 -289.84702)
		(end 59.6392 -289.84702)
		(width 0.18288)
		(layer "In6.Cu")
		(net "M_C_CPU1_SA_DQ<11>")
	)
	(segment
		(start 53.921406 -293.766748)
		(end 53.921406 -294.025066)
		(width 0.18288)
		(layer "In6.Cu")
		(net "M_C_CPU1_SA_DQ<11>")
	)
	(arc
		(start 87.689944 -271.825212)
		(mid 87.642265 -272.008112)
		(end 87.511382 -272.14449)
		(width 0.088646)
		(layer "In6.Cu")
		(net "M_C_CPU1_SA_DQ<11>")
	)
	(arc
		(start 85.707982 -272.957544)
		(mid 85.429804 -272.887821)
		(end 85.153246 -272.96364)
		(width 0.088646)
		(layer "In6.Cu")
		(net "M_C_CPU1_SA_DQ<11>")
	)
	(arc
		(start 97.183194 -271.011396)
		(mid 97.010381 -270.989076)
		(end 96.84893 -270.923512)
		(width 0.088646)
		(layer "In6.Cu")
		(net "M_C_CPU1_SA_DQ<11>")
	)
	(arc
		(start 91.731592 -271.335754)
		(mid 91.544394 -271.385897)
		(end 91.357196 -271.335754)
		(width 0.088646)
		(layer "In6.Cu")
		(net "M_C_CPU1_SA_DQ<11>")
	)
	(arc
		(start 93.222064 -271.327118)
		(mid 92.945589 -271.259798)
		(end 92.671392 -271.335754)
		(width 0.088646)
		(layer "In6.Cu")
		(net "M_C_CPU1_SA_DQ<11>")
	)
	(arc
		(start 88.537796 -271.335754)
		(mid 88.255094 -271.259978)
		(end 87.972392 -271.335754)
		(width 0.088646)
		(layer "In6.Cu")
		(net "M_C_CPU1_SA_DQ<11>")
	)
	(arc
		(start 88.912192 -271.335754)
		(mid 88.724994 -271.385897)
		(end 88.537796 -271.335754)
		(width 0.088646)
		(layer "In6.Cu")
		(net "M_C_CPU1_SA_DQ<11>")
	)
	(arc
		(start 87.113364 -272.140934)
		(mid 86.836923 -272.073768)
		(end 86.562692 -272.14957)
		(width 0.088646)
		(layer "In6.Cu")
		(net "M_C_CPU1_SA_DQ<11>")
	)
	(arc
		(start 92.282264 -271.327118)
		(mid 92.005789 -271.259798)
		(end 91.731592 -271.335754)
		(width 0.088646)
		(layer "In6.Cu")
		(net "M_C_CPU1_SA_DQ<11>")
	)
	(arc
		(start 95.485204 -270.683736)
		(mid 95.300349 -270.636786)
		(end 95.116396 -270.687038)
		(width 0.088646)
		(layer "In6.Cu")
		(net "M_C_CPU1_SA_DQ<11>")
	)
	(arc
		(start 96.425004 -270.683736)
		(mid 96.240149 -270.636786)
		(end 96.056196 -270.687038)
		(width 0.088646)
		(layer "In6.Cu")
		(net "M_C_CPU1_SA_DQ<11>")
	)
	(arc
		(start 91.357196 -271.335754)
		(mid 91.074494 -271.259978)
		(end 90.791792 -271.335754)
		(width 0.088646)
		(layer "In6.Cu")
		(net "M_C_CPU1_SA_DQ<11>")
	)
	(arc
		(start 86.562692 -272.14957)
		(mid 86.359387 -272.350436)
		(end 86.280244 -272.625058)
		(width 0.088646)
		(layer "In6.Cu")
		(net "M_C_CPU1_SA_DQ<11>")
	)
	(arc
		(start 92.671392 -271.335754)
		(mid 92.484194 -271.385897)
		(end 92.296996 -271.335754)
		(width 0.088646)
		(layer "In6.Cu")
		(net "M_C_CPU1_SA_DQ<11>")
	)
	(arc
		(start 94.166436 -271.329658)
		(mid 93.888004 -271.259812)
		(end 93.611192 -271.335754)
		(width 0.088646)
		(layer "In6.Cu")
		(net "M_C_CPU1_SA_DQ<11>")
	)
	(arc
		(start 94.828106 -271.00784)
		(mid 94.811072 -271.093475)
		(end 94.762574 -271.166082)
		(width 0.088646)
		(layer "In6.Cu")
		(net "M_C_CPU1_SA_DQ<11>")
	)
	(arc
		(start 85.153246 -272.96364)
		(mid 85.091768 -273.004642)
		(end 85.036152 -273.053302)
		(width 0.088646)
		(layer "In6.Cu")
		(net "M_C_CPU1_SA_DQ<11>")
	)
	(arc
		(start 94.730824 -271.198086)
		(mid 94.645787 -271.272653)
		(end 94.551754 -271.3355)
		(width 0.088646)
		(layer "In6.Cu")
		(net "M_C_CPU1_SA_DQ<11>")
	)
	(arc
		(start 89.851992 -271.335754)
		(mid 89.664794 -271.385897)
		(end 89.477596 -271.335754)
		(width 0.088646)
		(layer "In6.Cu")
		(net "M_C_CPU1_SA_DQ<11>")
	)
	(arc
		(start 94.928944 -270.830802)
		(mid 94.887419 -270.881339)
		(end 94.856554 -270.939006)
		(width 0.088646)
		(layer "In6.Cu")
		(net "M_C_CPU1_SA_DQ<11>")
	)
	(arc
		(start 86.280244 -272.639282)
		(mid 86.232565 -272.822182)
		(end 86.101682 -272.95856)
		(width 0.088646)
		(layer "In6.Cu")
		(net "M_C_CPU1_SA_DQ<11>")
	)
	(arc
		(start 87.972392 -271.335754)
		(mid 87.768057 -271.538359)
		(end 87.689944 -271.815306)
		(width 0.088646)
		(layer "In6.Cu")
		(net "M_C_CPU1_SA_DQ<11>")
	)
	(arc
		(start 90.417396 -271.335754)
		(mid 90.134694 -271.259978)
		(end 89.851992 -271.335754)
		(width 0.088646)
		(layer "In6.Cu")
		(net "M_C_CPU1_SA_DQ<11>")
	)
	(arc
		(start 93.611192 -271.335754)
		(mid 93.423994 -271.385897)
		(end 93.236796 -271.335754)
		(width 0.088646)
		(layer "In6.Cu")
		(net "M_C_CPU1_SA_DQ<11>")
	)
	(arc
		(start 94.551246 -271.335754)
		(mid 94.364048 -271.385897)
		(end 94.17685 -271.335754)
		(width 0.088646)
		(layer "In6.Cu")
		(net "M_C_CPU1_SA_DQ<11>")
	)
	(arc
		(start 90.791792 -271.335754)
		(mid 90.604594 -271.385897)
		(end 90.417396 -271.335754)
		(width 0.088646)
		(layer "In6.Cu")
		(net "M_C_CPU1_SA_DQ<11>")
	)
	(arc
		(start 87.502492 -272.14957)
		(mid 87.315294 -272.199713)
		(end 87.128096 -272.14957)
		(width 0.088646)
		(layer "In6.Cu")
		(net "M_C_CPU1_SA_DQ<11>")
	)
	(arc
		(start 89.462864 -271.327118)
		(mid 89.186389 -271.259798)
		(end 88.912192 -271.335754)
		(width 0.088646)
		(layer "In6.Cu")
		(net "M_C_CPU1_SA_DQ<11>")
	)
	(arc
		(start 96.056196 -270.687038)
		(mid 95.776993 -270.762678)
		(end 95.496888 -270.69034)
		(width 0.088646)
		(layer "In6.Cu")
		(net "M_C_CPU1_SA_DQ<11>")
	)
	(arc
		(start 86.092792 -272.96364)
		(mid 85.905594 -273.013783)
		(end 85.718396 -272.96364)
		(width 0.088646)
		(layer "In6.Cu")
		(net "M_C_CPU1_SA_DQ<11>")
	)
	(arc
		(start 95.116396 -270.687038)
		(mid 95.01797 -270.75279)
		(end 94.928944 -270.830802)
		(width 0.088646)
		(layer "In6.Cu")
		(net "M_C_CPU1_SA_DQ<11>")
	)
	(segment
		(start 27.328114 -306.116736)
		(end 28.475178 -306.116736)
		(width 0.20066)
		(layer "F.Cu")
		(net "M_C_CPU1_SA_DQ<10>")
	)
	(segment
		(start 32.916876 -306.328572)
		(end 33.345374 -306.328572)
		(width 0.20066)
		(layer "F.Cu")
		(net "M_C_CPU1_SA_DQ<10>")
	)
	(segment
		(start 35.976814 -306.116736)
		(end 34.871914 -306.116736)
		(width 0.20066)
		(layer "F.Cu")
		(net "M_C_CPU1_SA_DQ<10>")
	)
	(segment
		(start 29.647642 -305.681634)
		(end 29.657802 -305.691794)
		(width 0.101854)
		(layer "F.Cu")
		(net "M_C_CPU1_SA_DQ<10>")
	)
	(segment
		(start 29.912818 -305.691794)
		(end 31.972758 -305.691794)
		(width 0.1016)
		(layer "F.Cu")
		(net "M_C_CPU1_SA_DQ<10>")
	)
	(segment
		(start 29.657802 -305.691794)
		(end 29.912818 -305.691794)
		(width 0.101854)
		(layer "F.Cu")
		(net "M_C_CPU1_SA_DQ<10>")
	)
	(segment
		(start 33.345374 -306.328572)
		(end 33.55721 -306.116736)
		(width 0.20066)
		(layer "F.Cu")
		(net "M_C_CPU1_SA_DQ<10>")
	)
	(segment
		(start 96.713294 -271.824958)
		(end 96.713548 -271.825212)
		(width 0.20066)
		(layer "F.Cu")
		(net "M_C_CPU1_SA_DQ<10>")
	)
	(segment
		(start 96.713294 -271.289272)
		(end 96.713294 -271.824958)
		(width 0.20066)
		(layer "F.Cu")
		(net "M_C_CPU1_SA_DQ<10>")
	)
	(segment
		(start 32.74949 -306.161186)
		(end 32.916876 -306.328572)
		(width 0.20066)
		(layer "F.Cu")
		(net "M_C_CPU1_SA_DQ<10>")
	)
	(segment
		(start 31.972758 -305.691794)
		(end 32.605726 -305.691794)
		(width 0.20066)
		(layer "F.Cu")
		(net "M_C_CPU1_SA_DQ<10>")
	)
	(segment
		(start 32.605726 -305.691794)
		(end 32.74949 -305.835558)
		(width 0.20066)
		(layer "F.Cu")
		(net "M_C_CPU1_SA_DQ<10>")
	)
	(segment
		(start 28.91028 -305.681634)
		(end 29.647642 -305.681634)
		(width 0.20066)
		(layer "F.Cu")
		(net "M_C_CPU1_SA_DQ<10>")
	)
	(segment
		(start 32.74949 -305.835558)
		(end 32.74949 -306.161186)
		(width 0.20066)
		(layer "F.Cu")
		(net "M_C_CPU1_SA_DQ<10>")
	)
	(segment
		(start 28.475178 -306.116736)
		(end 28.91028 -305.681634)
		(width 0.20066)
		(layer "F.Cu")
		(net "M_C_CPU1_SA_DQ<10>")
	)
	(segment
		(start 33.55721 -306.116736)
		(end 34.871914 -306.116736)
		(width 0.20066)
		(layer "F.Cu")
		(net "M_C_CPU1_SA_DQ<10>")
	)
	(segment
		(start 96.056196 -271.335754)
		(end 96.041464 -271.327118)
		(width 0.088646)
		(layer "In6.Cu")
		(net "M_C_CPU1_SA_DQ<10>")
	)
	(segment
		(start 47.751746 -297.839638)
		(end 47.568866 -298.022518)
		(width 0.18288)
		(layer "In6.Cu")
		(net "M_C_CPU1_SA_DQ<10>")
	)
	(segment
		(start 58.322464 -293.15664)
		(end 58.05805 -293.421054)
		(width 0.18288)
		(layer "In6.Cu")
		(net "M_C_CPU1_SA_DQ<10>")
	)
	(segment
		(start 83.009232 -275.731732)
		(end 79.14767 -277.33117)
		(width 0.18288)
		(layer "In6.Cu")
		(net "M_C_CPU1_SA_DQ<10>")
	)
	(segment
		(start 60.348876 -291.798756)
		(end 60.05576 -292.091872)
		(width 0.18288)
		(layer "In6.Cu")
		(net "M_C_CPU1_SA_DQ<10>")
	)
	(segment
		(start 47.568866 -298.022518)
		(end 47.568866 -298.708826)
		(width 0.18288)
		(layer "In6.Cu")
		(net "M_C_CPU1_SA_DQ<10>")
	)
	(segment
		(start 56.018176 -293.691564)
		(end 55.273956 -294.435784)
		(width 0.18288)
		(layer "In6.Cu")
		(net "M_C_CPU1_SA_DQ<10>")
	)
	(segment
		(start 58.322464 -292.93058)
		(end 58.322464 -293.15664)
		(width 0.18288)
		(layer "In6.Cu")
		(net "M_C_CPU1_SA_DQ<10>")
	)
	(segment
		(start 92.216478 -272.140934)
		(end 92.201746 -272.14957)
		(width 0.088646)
		(layer "In6.Cu")
		(net "M_C_CPU1_SA_DQ<10>")
	)
	(segment
		(start 55.273956 -294.435784)
		(end 55.273956 -295.204896)
		(width 0.18288)
		(layer "In6.Cu")
		(net "M_C_CPU1_SA_DQ<10>")
	)
	(segment
		(start 54.409594 -296.069258)
		(end 54.151022 -296.069258)
		(width 0.18288)
		(layer "In6.Cu")
		(net "M_C_CPU1_SA_DQ<10>")
	)
	(segment
		(start 85.343746 -273.97329)
		(end 85.28685 -274.030186)
		(width 0.088646)
		(layer "In6.Cu")
		(net "M_C_CPU1_SA_DQ<10>")
	)
	(segment
		(start 58.52922 -292.091872)
		(end 58.119518 -292.501574)
		(width 0.18288)
		(layer "In6.Cu")
		(net "M_C_CPU1_SA_DQ<10>")
	)
	(segment
		(start 61.000386 -291.798756)
		(end 60.348876 -291.798756)
		(width 0.18288)
		(layer "In6.Cu")
		(net "M_C_CPU1_SA_DQ<10>")
	)
	(segment
		(start 48.259746 -298.708826)
		(end 48.259746 -298.022518)
		(width 0.18288)
		(layer "In6.Cu")
		(net "M_C_CPU1_SA_DQ<10>")
	)
	(segment
		(start 57.83199 -293.421054)
		(end 57.629044 -293.218108)
		(width 0.18288)
		(layer "In6.Cu")
		(net "M_C_CPU1_SA_DQ<10>")
	)
	(segment
		(start 88.159844 -272.625058)
		(end 88.159844 -272.639282)
		(width 0.088646)
		(layer "In6.Cu")
		(net "M_C_CPU1_SA_DQ<10>")
	)
	(segment
		(start 96.086422 -271.353026)
		(end 96.056196 -271.335754)
		(width 0.088646)
		(layer "In6.Cu")
		(net "M_C_CPU1_SA_DQ<10>")
	)
	(segment
		(start 43.405552 -302.978312)
		(end 42.199814 -304.18405)
		(width 0.18288)
		(layer "In6.Cu")
		(net "M_C_CPU1_SA_DQ<10>")
	)
	(segment
		(start 53.662326 -296.557954)
		(end 53.662326 -296.816526)
		(width 0.18288)
		(layer "In6.Cu")
		(net "M_C_CPU1_SA_DQ<10>")
	)
	(segment
		(start 86.750144 -273.453098)
		(end 86.750144 -273.461734)
		(width 0.088646)
		(layer "In6.Cu")
		(net "M_C_CPU1_SA_DQ<10>")
	)
	(segment
		(start 47.385986 -298.891706)
		(end 46.087284 -298.891706)
		(width 0.18288)
		(layer "In6.Cu")
		(net "M_C_CPU1_SA_DQ<10>")
	)
	(segment
		(start 42.199814 -304.18405)
		(end 40.657526 -304.18405)
		(width 0.18288)
		(layer "In6.Cu")
		(net "M_C_CPU1_SA_DQ<10>")
	)
	(segment
		(start 64.318134 -291.037518)
		(end 62.859412 -291.037518)
		(width 0.18288)
		(layer "In6.Cu")
		(net "M_C_CPU1_SA_DQ<10>")
	)
	(segment
		(start 57.402984 -293.218108)
		(end 56.929528 -293.691564)
		(width 0.18288)
		(layer "In6.Cu")
		(net "M_C_CPU1_SA_DQ<10>")
	)
	(segment
		(start 85.28685 -274.030186)
		(end 85.28685 -274.346924)
		(width 0.088646)
		(layer "In6.Cu")
		(net "M_C_CPU1_SA_DQ<10>")
	)
	(segment
		(start 79.14767 -277.33117)
		(end 67.206368 -289.27298)
		(width 0.18288)
		(layer "In6.Cu")
		(net "M_C_CPU1_SA_DQ<10>")
	)
	(segment
		(start 37.41801 -306.567586)
		(end 36.427664 -306.567586)
		(width 0.18288)
		(layer "In6.Cu")
		(net "M_C_CPU1_SA_DQ<10>")
	)
	(segment
		(start 45.228002 -299.750988)
		(end 45.228002 -302.075342)
		(width 0.18288)
		(layer "In6.Cu")
		(net "M_C_CPU1_SA_DQ<10>")
	)
	(segment
		(start 57.629044 -293.218108)
		(end 57.402984 -293.218108)
		(width 0.18288)
		(layer "In6.Cu")
		(net "M_C_CPU1_SA_DQ<10>")
	)
	(segment
		(start 91.272106 -272.143474)
		(end 91.261692 -272.14957)
		(width 0.088646)
		(layer "In6.Cu")
		(net "M_C_CPU1_SA_DQ<10>")
	)
	(segment
		(start 39.938452 -304.903124)
		(end 39.082472 -304.903124)
		(width 0.18288)
		(layer "In6.Cu")
		(net "M_C_CPU1_SA_DQ<10>")
	)
	(segment
		(start 83.574636 -275.731732)
		(end 83.342988 -275.731732)
		(width 0.088646)
		(layer "In6.Cu")
		(net "M_C_CPU1_SA_DQ<10>")
	)
	(segment
		(start 48.442626 -298.891706)
		(end 48.259746 -298.708826)
		(width 0.18288)
		(layer "In6.Cu")
		(net "M_C_CPU1_SA_DQ<10>")
	)
	(segment
		(start 56.929528 -293.691564)
		(end 56.018176 -293.691564)
		(width 0.18288)
		(layer "In6.Cu")
		(net "M_C_CPU1_SA_DQ<10>")
	)
	(segment
		(start 50.762408 -297.191938)
		(end 49.06264 -298.891706)
		(width 0.18288)
		(layer "In6.Cu")
		(net "M_C_CPU1_SA_DQ<10>")
	)
	(segment
		(start 53.286914 -297.191938)
		(end 50.762408 -297.191938)
		(width 0.18288)
		(layer "In6.Cu")
		(net "M_C_CPU1_SA_DQ<10>")
	)
	(segment
		(start 48.259746 -298.022518)
		(end 48.076866 -297.839638)
		(width 0.18288)
		(layer "In6.Cu")
		(net "M_C_CPU1_SA_DQ<10>")
	)
	(segment
		(start 60.05576 -292.091872)
		(end 58.52922 -292.091872)
		(width 0.18288)
		(layer "In6.Cu")
		(net "M_C_CPU1_SA_DQ<10>")
	)
	(segment
		(start 95.030036 -272.14449)
		(end 95.021146 -272.14957)
		(width 0.088646)
		(layer "In6.Cu")
		(net "M_C_CPU1_SA_DQ<10>")
	)
	(segment
		(start 58.119518 -292.501574)
		(end 58.119518 -292.727634)
		(width 0.18288)
		(layer "In6.Cu")
		(net "M_C_CPU1_SA_DQ<10>")
	)
	(segment
		(start 62.859412 -291.037518)
		(end 61.78042 -292.11651)
		(width 0.18288)
		(layer "In6.Cu")
		(net "M_C_CPU1_SA_DQ<10>")
	)
	(segment
		(start 53.448712 -296.34434)
		(end 53.662326 -296.557954)
		(width 0.18288)
		(layer "In6.Cu")
		(net "M_C_CPU1_SA_DQ<10>")
	)
	(segment
		(start 58.119518 -292.727634)
		(end 58.322464 -292.93058)
		(width 0.18288)
		(layer "In6.Cu")
		(net "M_C_CPU1_SA_DQ<10>")
	)
	(segment
		(start 55.273956 -295.204896)
		(end 54.409594 -296.069258)
		(width 0.18288)
		(layer "In6.Cu")
		(net "M_C_CPU1_SA_DQ<10>")
	)
	(segment
		(start 44.325032 -302.978312)
		(end 43.405552 -302.978312)
		(width 0.18288)
		(layer "In6.Cu")
		(net "M_C_CPU1_SA_DQ<10>")
	)
	(segment
		(start 36.427664 -306.567586)
		(end 35.976814 -306.116736)
		(width 0.18288)
		(layer "In6.Cu")
		(net "M_C_CPU1_SA_DQ<10>")
	)
	(segment
		(start 93.156278 -272.140934)
		(end 93.141546 -272.14957)
		(width 0.088646)
		(layer "In6.Cu")
		(net "M_C_CPU1_SA_DQ<10>")
	)
	(segment
		(start 87.981282 -272.95856)
		(end 87.972392 -272.96364)
		(width 0.088646)
		(layer "In6.Cu")
		(net "M_C_CPU1_SA_DQ<10>")
	)
	(segment
		(start 96.713548 -271.825212)
		(end 96.086422 -271.353026)
		(width 0.088646)
		(layer "In6.Cu")
		(net "M_C_CPU1_SA_DQ<10>")
	)
	(segment
		(start 53.662326 -296.816526)
		(end 53.286914 -297.191938)
		(width 0.18288)
		(layer "In6.Cu")
		(net "M_C_CPU1_SA_DQ<10>")
	)
	(segment
		(start 39.082472 -304.903124)
		(end 37.41801 -306.567586)
		(width 0.18288)
		(layer "In6.Cu")
		(net "M_C_CPU1_SA_DQ<10>")
	)
	(segment
		(start 83.342988 -275.731732)
		(end 83.009232 -275.731732)
		(width 0.18288)
		(layer "In6.Cu")
		(net "M_C_CPU1_SA_DQ<10>")
	)
	(segment
		(start 53.448712 -296.085768)
		(end 53.448712 -296.34434)
		(width 0.18288)
		(layer "In6.Cu")
		(net "M_C_CPU1_SA_DQ<10>")
	)
	(segment
		(start 85.28685 -274.346924)
		(end 84.822284 -274.81149)
		(width 0.088646)
		(layer "In6.Cu")
		(net "M_C_CPU1_SA_DQ<10>")
	)
	(segment
		(start 89.00795 -272.14957)
		(end 88.997536 -272.143474)
		(width 0.088646)
		(layer "In6.Cu")
		(net "M_C_CPU1_SA_DQ<10>")
	)
	(segment
		(start 53.937408 -295.855644)
		(end 53.678836 -295.855644)
		(width 0.18288)
		(layer "In6.Cu")
		(net "M_C_CPU1_SA_DQ<10>")
	)
	(segment
		(start 54.151022 -296.069258)
		(end 53.937408 -295.855644)
		(width 0.18288)
		(layer "In6.Cu")
		(net "M_C_CPU1_SA_DQ<10>")
	)
	(segment
		(start 84.822284 -274.81149)
		(end 84.494878 -274.81149)
		(width 0.088646)
		(layer "In6.Cu")
		(net "M_C_CPU1_SA_DQ<10>")
	)
	(segment
		(start 40.657526 -304.18405)
		(end 39.938452 -304.903124)
		(width 0.18288)
		(layer "In6.Cu")
		(net "M_C_CPU1_SA_DQ<10>")
	)
	(segment
		(start 89.39276 -272.143474)
		(end 89.382346 -272.14957)
		(width 0.088646)
		(layer "In6.Cu")
		(net "M_C_CPU1_SA_DQ<10>")
	)
	(segment
		(start 49.06264 -298.891706)
		(end 48.442626 -298.891706)
		(width 0.18288)
		(layer "In6.Cu")
		(net "M_C_CPU1_SA_DQ<10>")
	)
	(segment
		(start 47.568866 -298.708826)
		(end 47.385986 -298.891706)
		(width 0.18288)
		(layer "In6.Cu")
		(net "M_C_CPU1_SA_DQ<10>")
	)
	(segment
		(start 85.637878 -273.76882)
		(end 85.623146 -273.777456)
		(width 0.088646)
		(layer "In6.Cu")
		(net "M_C_CPU1_SA_DQ<10>")
	)
	(segment
		(start 61.78042 -292.11651)
		(end 61.31814 -292.11651)
		(width 0.18288)
		(layer "In6.Cu")
		(net "M_C_CPU1_SA_DQ<10>")
	)
	(segment
		(start 45.228002 -302.075342)
		(end 44.325032 -302.978312)
		(width 0.18288)
		(layer "In6.Cu")
		(net "M_C_CPU1_SA_DQ<10>")
	)
	(segment
		(start 48.076866 -297.839638)
		(end 47.751746 -297.839638)
		(width 0.18288)
		(layer "In6.Cu")
		(net "M_C_CPU1_SA_DQ<10>")
	)
	(segment
		(start 61.31814 -292.11651)
		(end 61.000386 -291.798756)
		(width 0.18288)
		(layer "In6.Cu")
		(net "M_C_CPU1_SA_DQ<10>")
	)
	(segment
		(start 53.678836 -295.855644)
		(end 53.448712 -296.085768)
		(width 0.18288)
		(layer "In6.Cu")
		(net "M_C_CPU1_SA_DQ<10>")
	)
	(segment
		(start 87.032846 -272.96364)
		(end 87.02675 -272.967196)
		(width 0.088646)
		(layer "In6.Cu")
		(net "M_C_CPU1_SA_DQ<10>")
	)
	(segment
		(start 94.096078 -272.140934)
		(end 94.081346 -272.14957)
		(width 0.088646)
		(layer "In6.Cu")
		(net "M_C_CPU1_SA_DQ<10>")
	)
	(segment
		(start 46.087284 -298.891706)
		(end 45.228002 -299.750988)
		(width 0.18288)
		(layer "In6.Cu")
		(net "M_C_CPU1_SA_DQ<10>")
	)
	(segment
		(start 84.494878 -274.81149)
		(end 83.574636 -275.731732)
		(width 0.088646)
		(layer "In6.Cu")
		(net "M_C_CPU1_SA_DQ<10>")
	)
	(segment
		(start 90.887296 -272.14957)
		(end 90.872564 -272.140934)
		(width 0.088646)
		(layer "In6.Cu")
		(net "M_C_CPU1_SA_DQ<10>")
	)
	(segment
		(start 66.082672 -289.27298)
		(end 64.318134 -291.037518)
		(width 0.18288)
		(layer "In6.Cu")
		(net "M_C_CPU1_SA_DQ<10>")
	)
	(segment
		(start 67.206368 -289.27298)
		(end 66.082672 -289.27298)
		(width 0.18288)
		(layer "In6.Cu")
		(net "M_C_CPU1_SA_DQ<10>")
	)
	(segment
		(start 87.04326 -272.957544)
		(end 87.032846 -272.96364)
		(width 0.088646)
		(layer "In6.Cu")
		(net "M_C_CPU1_SA_DQ<10>")
	)
	(segment
		(start 58.05805 -293.421054)
		(end 57.83199 -293.421054)
		(width 0.18288)
		(layer "In6.Cu")
		(net "M_C_CPU1_SA_DQ<10>")
	)
	(segment
		(start 95.208598 -271.809718)
		(end 95.208598 -271.825212)
		(width 0.088646)
		(layer "In6.Cu")
		(net "M_C_CPU1_SA_DQ<10>")
	)
	(arc
		(start 93.70695 -272.14957)
		(mid 93.432721 -272.073645)
		(end 93.156278 -272.140934)
		(width 0.088646)
		(layer "In6.Cu")
		(net "M_C_CPU1_SA_DQ<10>")
	)
	(arc
		(start 91.261692 -272.14957)
		(mid 91.074494 -272.199713)
		(end 90.887296 -272.14957)
		(width 0.088646)
		(layer "In6.Cu")
		(net "M_C_CPU1_SA_DQ<10>")
	)
	(arc
		(start 95.021146 -272.14957)
		(mid 94.833948 -272.199713)
		(end 94.64675 -272.14957)
		(width 0.088646)
		(layer "In6.Cu")
		(net "M_C_CPU1_SA_DQ<10>")
	)
	(arc
		(start 89.382346 -272.14957)
		(mid 89.195148 -272.199713)
		(end 89.00795 -272.14957)
		(width 0.088646)
		(layer "In6.Cu")
		(net "M_C_CPU1_SA_DQ<10>")
	)
	(arc
		(start 86.750144 -273.461734)
		(mid 86.697874 -273.644099)
		(end 86.562946 -273.777456)
		(width 0.088646)
		(layer "In6.Cu")
		(net "M_C_CPU1_SA_DQ<10>")
	)
	(arc
		(start 86.18855 -273.777456)
		(mid 85.914351 -273.701621)
		(end 85.637878 -273.76882)
		(width 0.088646)
		(layer "In6.Cu")
		(net "M_C_CPU1_SA_DQ<10>")
	)
	(arc
		(start 87.597996 -272.96364)
		(mid 87.321437 -272.887897)
		(end 87.04326 -272.957544)
		(width 0.088646)
		(layer "In6.Cu")
		(net "M_C_CPU1_SA_DQ<10>")
	)
	(arc
		(start 88.442292 -272.14957)
		(mid 88.238987 -272.350436)
		(end 88.159844 -272.625058)
		(width 0.088646)
		(layer "In6.Cu")
		(net "M_C_CPU1_SA_DQ<10>")
	)
	(arc
		(start 88.159844 -272.639282)
		(mid 88.112165 -272.822182)
		(end 87.981282 -272.95856)
		(width 0.088646)
		(layer "In6.Cu")
		(net "M_C_CPU1_SA_DQ<10>")
	)
	(arc
		(start 87.02675 -272.967196)
		(mid 86.824163 -273.173547)
		(end 86.750144 -273.453098)
		(width 0.088646)
		(layer "In6.Cu")
		(net "M_C_CPU1_SA_DQ<10>")
	)
	(arc
		(start 85.623146 -273.777456)
		(mid 85.47917 -273.869272)
		(end 85.343746 -273.97329)
		(width 0.088646)
		(layer "In6.Cu")
		(net "M_C_CPU1_SA_DQ<10>")
	)
	(arc
		(start 91.82735 -272.14957)
		(mid 91.550537 -272.073734)
		(end 91.272106 -272.143474)
		(width 0.088646)
		(layer "In6.Cu")
		(net "M_C_CPU1_SA_DQ<10>")
	)
	(arc
		(start 89.947496 -272.14957)
		(mid 89.670937 -272.073861)
		(end 89.39276 -272.143474)
		(width 0.088646)
		(layer "In6.Cu")
		(net "M_C_CPU1_SA_DQ<10>")
	)
	(arc
		(start 86.562946 -273.777456)
		(mid 86.375748 -273.827599)
		(end 86.18855 -273.777456)
		(width 0.088646)
		(layer "In6.Cu")
		(net "M_C_CPU1_SA_DQ<10>")
	)
	(arc
		(start 94.64675 -272.14957)
		(mid 94.372521 -272.073645)
		(end 94.096078 -272.140934)
		(width 0.088646)
		(layer "In6.Cu")
		(net "M_C_CPU1_SA_DQ<10>")
	)
	(arc
		(start 87.972392 -272.96364)
		(mid 87.785194 -273.013783)
		(end 87.597996 -272.96364)
		(width 0.088646)
		(layer "In6.Cu")
		(net "M_C_CPU1_SA_DQ<10>")
	)
	(arc
		(start 96.041464 -271.327118)
		(mid 95.764989 -271.259798)
		(end 95.490792 -271.335754)
		(width 0.088646)
		(layer "In6.Cu")
		(net "M_C_CPU1_SA_DQ<10>")
	)
	(arc
		(start 94.081346 -272.14957)
		(mid 93.894148 -272.199713)
		(end 93.70695 -272.14957)
		(width 0.088646)
		(layer "In6.Cu")
		(net "M_C_CPU1_SA_DQ<10>")
	)
	(arc
		(start 92.76715 -272.14957)
		(mid 92.492921 -272.073645)
		(end 92.216478 -272.140934)
		(width 0.088646)
		(layer "In6.Cu")
		(net "M_C_CPU1_SA_DQ<10>")
	)
	(arc
		(start 90.321892 -272.14957)
		(mid 90.134694 -272.199713)
		(end 89.947496 -272.14957)
		(width 0.088646)
		(layer "In6.Cu")
		(net "M_C_CPU1_SA_DQ<10>")
	)
	(arc
		(start 90.872564 -272.140934)
		(mid 90.596123 -272.073768)
		(end 90.321892 -272.14957)
		(width 0.088646)
		(layer "In6.Cu")
		(net "M_C_CPU1_SA_DQ<10>")
	)
	(arc
		(start 95.208598 -271.825212)
		(mid 95.160919 -272.008112)
		(end 95.030036 -272.14449)
		(width 0.088646)
		(layer "In6.Cu")
		(net "M_C_CPU1_SA_DQ<10>")
	)
	(arc
		(start 93.141546 -272.14957)
		(mid 92.954348 -272.199713)
		(end 92.76715 -272.14957)
		(width 0.088646)
		(layer "In6.Cu")
		(net "M_C_CPU1_SA_DQ<10>")
	)
	(arc
		(start 92.201746 -272.14957)
		(mid 92.014548 -272.199713)
		(end 91.82735 -272.14957)
		(width 0.088646)
		(layer "In6.Cu")
		(net "M_C_CPU1_SA_DQ<10>")
	)
	(arc
		(start 88.997536 -272.143474)
		(mid 88.719104 -272.07366)
		(end 88.442292 -272.14957)
		(width 0.088646)
		(layer "In6.Cu")
		(net "M_C_CPU1_SA_DQ<10>")
	)
	(arc
		(start 95.490792 -271.335754)
		(mid 95.287969 -271.535985)
		(end 95.208598 -271.809718)
		(width 0.088646)
		(layer "In6.Cu")
		(net "M_C_CPU1_SA_DQ<10>")
	)
	(segment
		(start 25.259792 -316.555374)
		(end 25.432512 -316.382654)
		(width 0.20066)
		(layer "F.Cu")
		(net "M_C_CPU1_SA_DQ<0>")
	)
	(segment
		(start 24.801068 -316.555374)
		(end 25.259792 -316.555374)
		(width 0.20066)
		(layer "F.Cu")
		(net "M_C_CPU1_SA_DQ<0>")
	)
	(segment
		(start 92.484448 -278.614378)
		(end 92.484194 -279.150318)
		(width 0.20066)
		(layer "F.Cu")
		(net "M_C_CPU1_SA_DQ<0>")
	)
	(segment
		(start 25.642062 -315.883544)
		(end 26.20391 -315.883544)
		(width 0.20066)
		(layer "F.Cu")
		(net "M_C_CPU1_SA_DQ<0>")
	)
	(segment
		(start 26.20391 -315.883544)
		(end 26.212038 -315.891672)
		(width 0.101854)
		(layer "F.Cu")
		(net "M_C_CPU1_SA_DQ<0>")
	)
	(segment
		(start 24.562308 -316.316614)
		(end 24.801068 -316.555374)
		(width 0.20066)
		(layer "F.Cu")
		(net "M_C_CPU1_SA_DQ<0>")
	)
	(segment
		(start 28.529026 -315.891672)
		(end 28.977844 -315.891672)
		(width 0.20066)
		(layer "F.Cu")
		(net "M_C_CPU1_SA_DQ<0>")
	)
	(segment
		(start 31.876746 -316.316614)
		(end 30.771846 -316.316614)
		(width 0.20066)
		(layer "F.Cu")
		(net "M_C_CPU1_SA_DQ<0>")
	)
	(segment
		(start 25.432512 -316.093094)
		(end 25.642062 -315.883544)
		(width 0.20066)
		(layer "F.Cu")
		(net "M_C_CPU1_SA_DQ<0>")
	)
	(segment
		(start 25.432512 -316.382654)
		(end 25.432512 -316.093094)
		(width 0.20066)
		(layer "F.Cu")
		(net "M_C_CPU1_SA_DQ<0>")
	)
	(segment
		(start 23.228046 -316.316614)
		(end 24.562308 -316.316614)
		(width 0.20066)
		(layer "F.Cu")
		(net "M_C_CPU1_SA_DQ<0>")
	)
	(segment
		(start 29.402786 -316.316614)
		(end 30.771846 -316.316614)
		(width 0.20066)
		(layer "F.Cu")
		(net "M_C_CPU1_SA_DQ<0>")
	)
	(segment
		(start 26.459942 -315.891672)
		(end 28.529026 -315.891672)
		(width 0.1016)
		(layer "F.Cu")
		(net "M_C_CPU1_SA_DQ<0>")
	)
	(segment
		(start 28.977844 -315.891672)
		(end 29.402786 -316.316614)
		(width 0.20066)
		(layer "F.Cu")
		(net "M_C_CPU1_SA_DQ<0>")
	)
	(segment
		(start 26.212038 -315.891672)
		(end 26.459942 -315.891672)
		(width 0.101854)
		(layer "F.Cu")
		(net "M_C_CPU1_SA_DQ<0>")
	)
	(segment
		(start 43.81881 -318.441578)
		(end 39.88689 -318.441578)
		(width 0.18288)
		(layer "In4.Cu")
		(net "M_C_CPU1_SA_DQ<0>")
	)
	(segment
		(start 62.319154 -316.642496)
		(end 61.623956 -316.642496)
		(width 0.18288)
		(layer "In4.Cu")
		(net "M_C_CPU1_SA_DQ<0>")
	)
	(segment
		(start 85.878162 -288.400236)
		(end 84.128102 -290.150296)
		(width 0.18288)
		(layer "In4.Cu")
		(net "M_C_CPU1_SA_DQ<0>")
	)
	(segment
		(start 38.87343 -318.441578)
		(end 34.914078 -318.441578)
		(width 0.18288)
		(layer "In4.Cu")
		(net "M_C_CPU1_SA_DQ<0>")
	)
	(segment
		(start 58.275474 -317.719456)
		(end 58.013854 -317.457836)
		(width 0.18288)
		(layer "In4.Cu")
		(net "M_C_CPU1_SA_DQ<0>")
	)
	(segment
		(start 92.28836 -281.097482)
		(end 92.29725 -281.102562)
		(width 0.088646)
		(layer "In4.Cu")
		(net "M_C_CPU1_SA_DQ<0>")
	)
	(segment
		(start 62.780164 -316.451488)
		(end 62.319154 -316.642496)
		(width 0.18288)
		(layer "In4.Cu")
		(net "M_C_CPU1_SA_DQ<0>")
	)
	(segment
		(start 39.03345 -317.951612)
		(end 39.03345 -318.281558)
		(width 0.18288)
		(layer "In4.Cu")
		(net "M_C_CPU1_SA_DQ<0>")
	)
	(segment
		(start 92.484194 -279.150318)
		(end 92.506546 -279.16759)
		(width 0.088646)
		(layer "In4.Cu")
		(net "M_C_CPU1_SA_DQ<0>")
	)
	(segment
		(start 86.189058 -288.400236)
		(end 85.878162 -288.400236)
		(width 0.18288)
		(layer "In4.Cu")
		(net "M_C_CPU1_SA_DQ<0>")
	)
	(segment
		(start 39.03345 -318.281558)
		(end 38.87343 -318.441578)
		(width 0.18288)
		(layer "In4.Cu")
		(net "M_C_CPU1_SA_DQ<0>")
	)
	(segment
		(start 89.00795 -286.151066)
		(end 88.99906 -286.156146)
		(width 0.088646)
		(layer "In4.Cu")
		(net "M_C_CPU1_SA_DQ<0>")
	)
	(segment
		(start 34.914078 -318.441578)
		(end 33.214056 -316.741556)
		(width 0.18288)
		(layer "In4.Cu")
		(net "M_C_CPU1_SA_DQ<0>")
	)
	(segment
		(start 91.639644 -283.219906)
		(end 91.639644 -283.229812)
		(width 0.088646)
		(layer "In4.Cu")
		(net "M_C_CPU1_SA_DQ<0>")
	)
	(segment
		(start 87.502492 -287.778698)
		(end 87.502746 -287.778444)
		(width 0.088646)
		(layer "In4.Cu")
		(net "M_C_CPU1_SA_DQ<0>")
	)
	(segment
		(start 92.579444 -281.576526)
		(end 92.579444 -281.607514)
		(width 0.088646)
		(layer "In4.Cu")
		(net "M_C_CPU1_SA_DQ<0>")
	)
	(segment
		(start 88.350344 -287.28924)
		(end 88.350344 -287.299146)
		(width 0.088646)
		(layer "In4.Cu")
		(net "M_C_CPU1_SA_DQ<0>")
	)
	(segment
		(start 63.410338 -315.821314)
		(end 62.780164 -316.451488)
		(width 0.18288)
		(layer "In4.Cu")
		(net "M_C_CPU1_SA_DQ<0>")
	)
	(segment
		(start 84.128102 -290.150296)
		(end 80.556608 -298.77131)
		(width 0.18288)
		(layer "In4.Cu")
		(net "M_C_CPU1_SA_DQ<0>")
	)
	(segment
		(start 33.214056 -316.741556)
		(end 32.301688 -316.741556)
		(width 0.18288)
		(layer "In4.Cu")
		(net "M_C_CPU1_SA_DQ<0>")
	)
	(segment
		(start 92.506546 -279.16759)
		(end 92.579698 -279.766268)
		(width 0.088646)
		(layer "In4.Cu")
		(net "M_C_CPU1_SA_DQ<0>")
	)
	(segment
		(start 89.290144 -285.661354)
		(end 89.290144 -285.683452)
		(width 0.088646)
		(layer "In4.Cu")
		(net "M_C_CPU1_SA_DQ<0>")
	)
	(segment
		(start 39.72687 -318.281558)
		(end 39.72687 -317.951612)
		(width 0.18288)
		(layer "In4.Cu")
		(net "M_C_CPU1_SA_DQ<0>")
	)
	(segment
		(start 92.579698 -279.766268)
		(end 92.579698 -279.982676)
		(width 0.088646)
		(layer "In4.Cu")
		(net "M_C_CPU1_SA_DQ<0>")
	)
	(segment
		(start 58.013854 -317.457836)
		(end 56.209184 -317.457836)
		(width 0.18288)
		(layer "In4.Cu")
		(net "M_C_CPU1_SA_DQ<0>")
	)
	(segment
		(start 89.477596 -285.336996)
		(end 89.468706 -285.342076)
		(width 0.088646)
		(layer "In4.Cu")
		(net "M_C_CPU1_SA_DQ<0>")
	)
	(segment
		(start 39.19347 -317.791592)
		(end 39.03345 -317.951612)
		(width 0.18288)
		(layer "In4.Cu")
		(net "M_C_CPU1_SA_DQ<0>")
	)
	(segment
		(start 74.074274 -307.671978)
		(end 65.924938 -315.821314)
		(width 0.18288)
		(layer "In4.Cu")
		(net "M_C_CPU1_SA_DQ<0>")
	)
	(segment
		(start 91.357196 -283.709364)
		(end 91.348306 -283.714444)
		(width 0.088646)
		(layer "In4.Cu")
		(net "M_C_CPU1_SA_DQ<0>")
	)
	(segment
		(start 55.484522 -318.182498)
		(end 53.636418 -318.182498)
		(width 0.18288)
		(layer "In4.Cu")
		(net "M_C_CPU1_SA_DQ<0>")
	)
	(segment
		(start 65.924938 -315.821314)
		(end 63.410338 -315.821314)
		(width 0.18288)
		(layer "In4.Cu")
		(net "M_C_CPU1_SA_DQ<0>")
	)
	(segment
		(start 46.122844 -319.291208)
		(end 43.81881 -318.441578)
		(width 0.18288)
		(layer "In4.Cu")
		(net "M_C_CPU1_SA_DQ<0>")
	)
	(segment
		(start 50.550572 -319.016634)
		(end 50.275998 -319.291208)
		(width 0.18288)
		(layer "In4.Cu")
		(net "M_C_CPU1_SA_DQ<0>")
	)
	(segment
		(start 92.29725 -282.081478)
		(end 92.28836 -282.086558)
		(width 0.088646)
		(layer "In4.Cu")
		(net "M_C_CPU1_SA_DQ<0>")
	)
	(segment
		(start 50.275998 -319.291208)
		(end 46.122844 -319.291208)
		(width 0.18288)
		(layer "In4.Cu")
		(net "M_C_CPU1_SA_DQ<0>")
	)
	(segment
		(start 56.209184 -317.457836)
		(end 55.484522 -318.182498)
		(width 0.18288)
		(layer "In4.Cu")
		(net "M_C_CPU1_SA_DQ<0>")
	)
	(segment
		(start 74.074274 -305.253644)
		(end 74.074274 -307.671978)
		(width 0.18288)
		(layer "In4.Cu")
		(net "M_C_CPU1_SA_DQ<0>")
	)
	(segment
		(start 80.556608 -298.77131)
		(end 74.074274 -305.253644)
		(width 0.18288)
		(layer "In4.Cu")
		(net "M_C_CPU1_SA_DQ<0>")
	)
	(segment
		(start 89.760044 -284.847538)
		(end 89.760044 -284.857444)
		(width 0.088646)
		(layer "In4.Cu")
		(net "M_C_CPU1_SA_DQ<0>")
	)
	(segment
		(start 60.128404 -317.50508)
		(end 59.622944 -317.71463)
		(width 0.18288)
		(layer "In4.Cu")
		(net "M_C_CPU1_SA_DQ<0>")
	)
	(segment
		(start 91.169744 -284.033722)
		(end 91.169744 -284.043628)
		(width 0.088646)
		(layer "In4.Cu")
		(net "M_C_CPU1_SA_DQ<0>")
	)
	(segment
		(start 87.050118 -287.838134)
		(end 86.487508 -288.400236)
		(width 0.088646)
		(layer "In4.Cu")
		(net "M_C_CPU1_SA_DQ<0>")
	)
	(segment
		(start 39.56685 -317.791592)
		(end 39.19347 -317.791592)
		(width 0.18288)
		(layer "In4.Cu")
		(net "M_C_CPU1_SA_DQ<0>")
	)
	(segment
		(start 52.802282 -319.016634)
		(end 50.550572 -319.016634)
		(width 0.18288)
		(layer "In4.Cu")
		(net "M_C_CPU1_SA_DQ<0>")
	)
	(segment
		(start 32.301688 -316.741556)
		(end 31.876746 -316.316614)
		(width 0.18288)
		(layer "In4.Cu")
		(net "M_C_CPU1_SA_DQ<0>")
	)
	(segment
		(start 88.549988 -286.95777)
		(end 88.537796 -286.964882)
		(width 0.088646)
		(layer "In4.Cu")
		(net "M_C_CPU1_SA_DQ<0>")
	)
	(segment
		(start 39.72687 -317.951612)
		(end 39.56685 -317.791592)
		(width 0.18288)
		(layer "In4.Cu")
		(net "M_C_CPU1_SA_DQ<0>")
	)
	(segment
		(start 91.827096 -282.895548)
		(end 91.818206 -282.900628)
		(width 0.088646)
		(layer "In4.Cu")
		(net "M_C_CPU1_SA_DQ<0>")
	)
	(segment
		(start 59.611006 -317.719456)
		(end 58.275474 -317.719456)
		(width 0.18288)
		(layer "In4.Cu")
		(net "M_C_CPU1_SA_DQ<0>")
	)
	(segment
		(start 89.947496 -284.52318)
		(end 89.938606 -284.52826)
		(width 0.088646)
		(layer "In4.Cu")
		(net "M_C_CPU1_SA_DQ<0>")
	)
	(segment
		(start 86.487508 -288.400236)
		(end 86.189058 -288.400236)
		(width 0.088646)
		(layer "In4.Cu")
		(net "M_C_CPU1_SA_DQ<0>")
	)
	(segment
		(start 61.623956 -316.642496)
		(end 61.20892 -317.057532)
		(width 0.18288)
		(layer "In4.Cu")
		(net "M_C_CPU1_SA_DQ<0>")
	)
	(segment
		(start 61.20892 -317.057532)
		(end 60.128404 -317.50508)
		(width 0.18288)
		(layer "In4.Cu")
		(net "M_C_CPU1_SA_DQ<0>")
	)
	(segment
		(start 88.537796 -286.964882)
		(end 88.528906 -286.969962)
		(width 0.088646)
		(layer "In4.Cu")
		(net "M_C_CPU1_SA_DQ<0>")
	)
	(segment
		(start 92.29725 -280.453846)
		(end 92.28836 -280.458926)
		(width 0.088646)
		(layer "In4.Cu")
		(net "M_C_CPU1_SA_DQ<0>")
	)
	(segment
		(start 53.636418 -318.182498)
		(end 52.802282 -319.016634)
		(width 0.18288)
		(layer "In4.Cu")
		(net "M_C_CPU1_SA_DQ<0>")
	)
	(segment
		(start 39.88689 -318.441578)
		(end 39.72687 -318.281558)
		(width 0.18288)
		(layer "In4.Cu")
		(net "M_C_CPU1_SA_DQ<0>")
	)
	(segment
		(start 59.622944 -317.71463)
		(end 59.611006 -317.719456)
		(width 0.18288)
		(layer "In4.Cu")
		(net "M_C_CPU1_SA_DQ<0>")
	)
	(segment
		(start 92.109798 -282.405836)
		(end 92.109798 -282.42006)
		(width 0.088646)
		(layer "In4.Cu")
		(net "M_C_CPU1_SA_DQ<0>")
	)
	(arc
		(start 91.169744 -284.043628)
		(mid 91.091633 -284.320577)
		(end 90.887296 -284.52318)
		(width 0.088646)
		(layer "In4.Cu")
		(net "M_C_CPU1_SA_DQ<0>")
	)
	(arc
		(start 88.350344 -287.299146)
		(mid 88.272233 -287.576095)
		(end 88.067896 -287.778698)
		(width 0.088646)
		(layer "In4.Cu")
		(net "M_C_CPU1_SA_DQ<0>")
	)
	(arc
		(start 91.639644 -283.229812)
		(mid 91.561533 -283.506761)
		(end 91.357196 -283.709364)
		(width 0.088646)
		(layer "In4.Cu")
		(net "M_C_CPU1_SA_DQ<0>")
	)
	(arc
		(start 88.067896 -287.778698)
		(mid 87.785194 -287.854474)
		(end 87.502492 -287.778698)
		(width 0.088646)
		(layer "In4.Cu")
		(net "M_C_CPU1_SA_DQ<0>")
	)
	(arc
		(start 90.887296 -284.52318)
		(mid 90.604594 -284.598956)
		(end 90.321892 -284.52318)
		(width 0.088646)
		(layer "In4.Cu")
		(net "M_C_CPU1_SA_DQ<0>")
	)
	(arc
		(start 92.28836 -282.086558)
		(mid 92.157446 -282.222918)
		(end 92.109798 -282.405836)
		(width 0.088646)
		(layer "In4.Cu")
		(net "M_C_CPU1_SA_DQ<0>")
	)
	(arc
		(start 88.99906 -286.156146)
		(mid 88.868146 -286.292506)
		(end 88.820498 -286.475424)
		(width 0.088646)
		(layer "In4.Cu")
		(net "M_C_CPU1_SA_DQ<0>")
	)
	(arc
		(start 92.579444 -281.607514)
		(mid 92.500074 -281.881248)
		(end 92.29725 -282.081478)
		(width 0.088646)
		(layer "In4.Cu")
		(net "M_C_CPU1_SA_DQ<0>")
	)
	(arc
		(start 91.818206 -282.900628)
		(mid 91.687292 -283.036988)
		(end 91.639644 -283.219906)
		(width 0.088646)
		(layer "In4.Cu")
		(net "M_C_CPU1_SA_DQ<0>")
	)
	(arc
		(start 92.109798 -282.42006)
		(mid 92.030579 -282.694745)
		(end 91.827096 -282.895548)
		(width 0.088646)
		(layer "In4.Cu")
		(net "M_C_CPU1_SA_DQ<0>")
	)
	(arc
		(start 92.29725 -281.102562)
		(mid 92.500073 -281.302793)
		(end 92.579444 -281.576526)
		(width 0.088646)
		(layer "In4.Cu")
		(net "M_C_CPU1_SA_DQ<0>")
	)
	(arc
		(start 88.820498 -286.475424)
		(mid 88.748263 -286.751948)
		(end 88.549988 -286.95777)
		(width 0.088646)
		(layer "In4.Cu")
		(net "M_C_CPU1_SA_DQ<0>")
	)
	(arc
		(start 91.348306 -283.714444)
		(mid 91.217392 -283.850804)
		(end 91.169744 -284.033722)
		(width 0.088646)
		(layer "In4.Cu")
		(net "M_C_CPU1_SA_DQ<0>")
	)
	(arc
		(start 89.760044 -284.857444)
		(mid 89.681933 -285.134393)
		(end 89.477596 -285.336996)
		(width 0.088646)
		(layer "In4.Cu")
		(net "M_C_CPU1_SA_DQ<0>")
	)
	(arc
		(start 92.28836 -280.458926)
		(mid 92.109763 -280.778204)
		(end 92.28836 -281.097482)
		(width 0.088646)
		(layer "In4.Cu")
		(net "M_C_CPU1_SA_DQ<0>")
	)
	(arc
		(start 90.321892 -284.52318)
		(mid 90.134694 -284.473037)
		(end 89.947496 -284.52318)
		(width 0.088646)
		(layer "In4.Cu")
		(net "M_C_CPU1_SA_DQ<0>")
	)
	(arc
		(start 87.502746 -287.778444)
		(mid 87.31515 -287.728081)
		(end 87.127588 -287.778444)
		(width 0.088646)
		(layer "In4.Cu")
		(net "M_C_CPU1_SA_DQ<0>")
	)
	(arc
		(start 89.468706 -285.342076)
		(mid 89.337792 -285.478436)
		(end 89.290144 -285.661354)
		(width 0.088646)
		(layer "In4.Cu")
		(net "M_C_CPU1_SA_DQ<0>")
	)
	(arc
		(start 89.290144 -285.683452)
		(mid 89.209233 -285.95358)
		(end 89.00795 -286.151066)
		(width 0.088646)
		(layer "In4.Cu")
		(net "M_C_CPU1_SA_DQ<0>")
	)
	(arc
		(start 88.528906 -286.969962)
		(mid 88.397992 -287.106322)
		(end 88.350344 -287.28924)
		(width 0.088646)
		(layer "In4.Cu")
		(net "M_C_CPU1_SA_DQ<0>")
	)
	(arc
		(start 89.938606 -284.52826)
		(mid 89.807692 -284.66462)
		(end 89.760044 -284.847538)
		(width 0.088646)
		(layer "In4.Cu")
		(net "M_C_CPU1_SA_DQ<0>")
	)
	(arc
		(start 87.127588 -287.778444)
		(mid 87.086901 -287.805755)
		(end 87.050118 -287.838134)
		(width 0.088646)
		(layer "In4.Cu")
		(net "M_C_CPU1_SA_DQ<0>")
	)
	(arc
		(start 92.579698 -279.982676)
		(mid 92.499536 -280.254865)
		(end 92.29725 -280.453846)
		(width 0.088646)
		(layer "In4.Cu")
		(net "M_C_CPU1_SA_DQ<0>")
	)
	(segment
		(start 34.871914 -267.016738)
		(end 35.976814 -267.016738)
		(width 0.20066)
		(layer "F.Cu")
		(net "M_C_CPU1_SA_CS_N<3>")
	)
	(segment
		(start 93.893894 -258.2672)
		(end 93.893894 -258.802886)
		(width 0.20066)
		(layer "F.Cu")
		(net "M_C_CPU1_SA_CS_N<3>")
	)
	(segment
		(start 93.893894 -258.802886)
		(end 93.894148 -258.80314)
		(width 0.20066)
		(layer "F.Cu")
		(net "M_C_CPU1_SA_CS_N<3>")
	)
	(segment
		(start 57.306464 -265.558778)
		(end 57.306464 -265.174984)
		(width 0.18288)
		(layer "In4.Cu")
		(net "M_C_CPU1_SA_CS_N<3>")
	)
	(segment
		(start 56.613044 -265.174984)
		(end 56.613044 -265.558778)
		(width 0.18288)
		(layer "In4.Cu")
		(net "M_C_CPU1_SA_CS_N<3>")
	)
	(segment
		(start 85.435694 -257.550158)
		(end 85.08238 -257.550158)
		(width 0.088646)
		(layer "In4.Cu")
		(net "M_C_CPU1_SA_CS_N<3>")
	)
	(segment
		(start 91.169998 -257.997706)
		(end 91.169998 -257.98907)
		(width 0.088646)
		(layer "In4.Cu")
		(net "M_C_CPU1_SA_CS_N<3>")
	)
	(segment
		(start 56.795924 -264.992104)
		(end 56.613044 -265.174984)
		(width 0.18288)
		(layer "In4.Cu")
		(net "M_C_CPU1_SA_CS_N<3>")
	)
	(segment
		(start 90.893392 -257.503168)
		(end 90.887296 -257.499612)
		(width 0.088646)
		(layer "In4.Cu")
		(net "M_C_CPU1_SA_CS_N<3>")
	)
	(segment
		(start 57.123584 -264.992104)
		(end 56.795924 -264.992104)
		(width 0.18288)
		(layer "In4.Cu")
		(net "M_C_CPU1_SA_CS_N<3>")
	)
	(segment
		(start 40.621712 -266.592304)
		(end 39.770812 -267.443204)
		(width 0.18288)
		(layer "In4.Cu")
		(net "M_C_CPU1_SA_CS_N<3>")
	)
	(segment
		(start 58.468006 -265.741658)
		(end 57.489344 -265.741658)
		(width 0.18288)
		(layer "In4.Cu")
		(net "M_C_CPU1_SA_CS_N<3>")
	)
	(segment
		(start 83.697064 -257.31597)
		(end 82.829654 -258.18338)
		(width 0.18288)
		(layer "In4.Cu")
		(net "M_C_CPU1_SA_CS_N<3>")
	)
	(segment
		(start 63.013082 -264.663936)
		(end 59.545728 -264.663936)
		(width 0.18288)
		(layer "In4.Cu")
		(net "M_C_CPU1_SA_CS_N<3>")
	)
	(segment
		(start 56.613044 -265.558778)
		(end 56.430164 -265.741658)
		(width 0.18288)
		(layer "In4.Cu")
		(net "M_C_CPU1_SA_CS_N<3>")
	)
	(segment
		(start 68.147184 -261.643876)
		(end 66.366898 -263.424162)
		(width 0.18288)
		(layer "In4.Cu")
		(net "M_C_CPU1_SA_CS_N<3>")
	)
	(segment
		(start 64.624204 -263.864344)
		(end 63.812674 -263.864344)
		(width 0.18288)
		(layer "In4.Cu")
		(net "M_C_CPU1_SA_CS_N<3>")
	)
	(segment
		(start 43.795696 -266.592304)
		(end 40.621712 -266.592304)
		(width 0.18288)
		(layer "In4.Cu")
		(net "M_C_CPU1_SA_CS_N<3>")
	)
	(segment
		(start 56.430164 -265.741658)
		(end 44.646342 -265.741658)
		(width 0.18288)
		(layer "In4.Cu")
		(net "M_C_CPU1_SA_CS_N<3>")
	)
	(segment
		(start 76.469748 -258.18338)
		(end 68.147184 -261.643876)
		(width 0.18288)
		(layer "In4.Cu")
		(net "M_C_CPU1_SA_CS_N<3>")
	)
	(segment
		(start 39.770812 -267.443204)
		(end 36.40328 -267.443204)
		(width 0.18288)
		(layer "In4.Cu")
		(net "M_C_CPU1_SA_CS_N<3>")
	)
	(segment
		(start 90.887296 -257.499612)
		(end 90.872564 -257.490976)
		(width 0.088646)
		(layer "In4.Cu")
		(net "M_C_CPU1_SA_CS_N<3>")
	)
	(segment
		(start 63.812674 -263.864344)
		(end 63.013082 -264.663936)
		(width 0.18288)
		(layer "In4.Cu")
		(net "M_C_CPU1_SA_CS_N<3>")
	)
	(segment
		(start 82.829654 -258.18338)
		(end 76.469748 -258.18338)
		(width 0.18288)
		(layer "In4.Cu")
		(net "M_C_CPU1_SA_CS_N<3>")
	)
	(segment
		(start 44.646342 -265.741658)
		(end 43.795696 -266.592304)
		(width 0.18288)
		(layer "In4.Cu")
		(net "M_C_CPU1_SA_CS_N<3>")
	)
	(segment
		(start 65.064386 -263.424162)
		(end 64.624204 -263.864344)
		(width 0.18288)
		(layer "In4.Cu")
		(net "M_C_CPU1_SA_CS_N<3>")
	)
	(segment
		(start 59.545728 -264.663936)
		(end 58.468006 -265.741658)
		(width 0.18288)
		(layer "In4.Cu")
		(net "M_C_CPU1_SA_CS_N<3>")
	)
	(segment
		(start 66.366898 -263.424162)
		(end 65.064386 -263.424162)
		(width 0.18288)
		(layer "In4.Cu")
		(net "M_C_CPU1_SA_CS_N<3>")
	)
	(segment
		(start 36.40328 -267.443204)
		(end 35.976814 -267.016738)
		(width 0.18288)
		(layer "In4.Cu")
		(net "M_C_CPU1_SA_CS_N<3>")
	)
	(segment
		(start 92.875608 -258.381246)
		(end 91.610434 -258.381246)
		(width 0.088646)
		(layer "In4.Cu")
		(net "M_C_CPU1_SA_CS_N<3>")
	)
	(segment
		(start 84.434934 -257.31597)
		(end 83.697064 -257.31597)
		(width 0.18288)
		(layer "In4.Cu")
		(net "M_C_CPU1_SA_CS_N<3>")
	)
	(segment
		(start 57.306464 -265.174984)
		(end 57.123584 -264.992104)
		(width 0.18288)
		(layer "In4.Cu")
		(net "M_C_CPU1_SA_CS_N<3>")
	)
	(segment
		(start 84.848192 -257.31597)
		(end 84.434934 -257.31597)
		(width 0.088646)
		(layer "In4.Cu")
		(net "M_C_CPU1_SA_CS_N<3>")
	)
	(segment
		(start 57.489344 -265.741658)
		(end 57.306464 -265.558778)
		(width 0.18288)
		(layer "In4.Cu")
		(net "M_C_CPU1_SA_CS_N<3>")
	)
	(segment
		(start 85.08238 -257.550158)
		(end 84.848192 -257.31597)
		(width 0.088646)
		(layer "In4.Cu")
		(net "M_C_CPU1_SA_CS_N<3>")
	)
	(arc
		(start 91.357196 -258.313428)
		(mid 91.222263 -258.180074)
		(end 91.169998 -257.997706)
		(width 0.088646)
		(layer "In4.Cu")
		(net "M_C_CPU1_SA_CS_N<3>")
	)
	(arc
		(start 89.007696 -257.499612)
		(mid 88.724994 -257.423836)
		(end 88.442292 -257.499612)
		(width 0.088646)
		(layer "In4.Cu")
		(net "M_C_CPU1_SA_CS_N<3>")
	)
	(arc
		(start 93.894148 -258.80314)
		(mid 93.426838 -258.490893)
		(end 92.875608 -258.381246)
		(width 0.088646)
		(layer "In4.Cu")
		(net "M_C_CPU1_SA_CS_N<3>")
	)
	(arc
		(start 88.067896 -257.499612)
		(mid 87.785194 -257.423836)
		(end 87.502492 -257.499612)
		(width 0.088646)
		(layer "In4.Cu")
		(net "M_C_CPU1_SA_CS_N<3>")
	)
	(arc
		(start 89.382092 -257.499612)
		(mid 89.194894 -257.549755)
		(end 89.007696 -257.499612)
		(width 0.088646)
		(layer "In4.Cu")
		(net "M_C_CPU1_SA_CS_N<3>")
	)
	(arc
		(start 86.562692 -257.499612)
		(mid 86.375494 -257.549755)
		(end 86.188296 -257.499612)
		(width 0.088646)
		(layer "In4.Cu")
		(net "M_C_CPU1_SA_CS_N<3>")
	)
	(arc
		(start 87.502492 -257.499612)
		(mid 87.315294 -257.549755)
		(end 87.128096 -257.499612)
		(width 0.088646)
		(layer "In4.Cu")
		(net "M_C_CPU1_SA_CS_N<3>")
	)
	(arc
		(start 91.169998 -257.98907)
		(mid 91.096007 -257.709504)
		(end 90.893392 -257.503168)
		(width 0.088646)
		(layer "In4.Cu")
		(net "M_C_CPU1_SA_CS_N<3>")
	)
	(arc
		(start 86.188296 -257.499612)
		(mid 85.905594 -257.423836)
		(end 85.622892 -257.499612)
		(width 0.088646)
		(layer "In4.Cu")
		(net "M_C_CPU1_SA_CS_N<3>")
	)
	(arc
		(start 87.128096 -257.499612)
		(mid 86.845394 -257.423836)
		(end 86.562692 -257.499612)
		(width 0.088646)
		(layer "In4.Cu")
		(net "M_C_CPU1_SA_CS_N<3>")
	)
	(arc
		(start 91.610434 -258.381246)
		(mid 91.479357 -258.363991)
		(end 91.357196 -258.313428)
		(width 0.088646)
		(layer "In4.Cu")
		(net "M_C_CPU1_SA_CS_N<3>")
	)
	(arc
		(start 89.947496 -257.499612)
		(mid 89.664794 -257.423836)
		(end 89.382092 -257.499612)
		(width 0.088646)
		(layer "In4.Cu")
		(net "M_C_CPU1_SA_CS_N<3>")
	)
	(arc
		(start 85.622892 -257.499612)
		(mid 85.53262 -257.537211)
		(end 85.435694 -257.550158)
		(width 0.088646)
		(layer "In4.Cu")
		(net "M_C_CPU1_SA_CS_N<3>")
	)
	(arc
		(start 90.872564 -257.490976)
		(mid 90.596089 -257.423656)
		(end 90.321892 -257.499612)
		(width 0.088646)
		(layer "In4.Cu")
		(net "M_C_CPU1_SA_CS_N<3>")
	)
	(arc
		(start 90.321892 -257.499612)
		(mid 90.134694 -257.549755)
		(end 89.947496 -257.499612)
		(width 0.088646)
		(layer "In4.Cu")
		(net "M_C_CPU1_SA_CS_N<3>")
	)
	(arc
		(start 88.442292 -257.499612)
		(mid 88.255094 -257.549755)
		(end 88.067896 -257.499612)
		(width 0.088646)
		(layer "In4.Cu")
		(net "M_C_CPU1_SA_CS_N<3>")
	)
	(segment
		(start 30.771846 -267.866622)
		(end 31.876746 -267.866622)
		(width 0.20066)
		(layer "F.Cu")
		(net "M_C_CPU1_SA_CS_N<2>")
	)
	(segment
		(start 93.424248 -259.616702)
		(end 93.423994 -259.616956)
		(width 0.20066)
		(layer "F.Cu")
		(net "M_C_CPU1_SA_CS_N<2>")
	)
	(segment
		(start 93.424248 -259.081016)
		(end 93.424248 -259.616702)
		(width 0.20066)
		(layer "F.Cu")
		(net "M_C_CPU1_SA_CS_N<2>")
	)
	(segment
		(start 62.93866 -266.914376)
		(end 62.411356 -267.44168)
		(width 0.18288)
		(layer "In4.Cu")
		(net "M_C_CPU1_SA_CS_N<2>")
	)
	(segment
		(start 35.095942 -269.14221)
		(end 34.24555 -268.291818)
		(width 0.18288)
		(layer "In4.Cu")
		(net "M_C_CPU1_SA_CS_N<2>")
	)
	(segment
		(start 62.93866 -266.493244)
		(end 62.93866 -266.914376)
		(width 0.18288)
		(layer "In4.Cu")
		(net "M_C_CPU1_SA_CS_N<2>")
	)
	(segment
		(start 39.832534 -269.14221)
		(end 35.095942 -269.14221)
		(width 0.18288)
		(layer "In4.Cu")
		(net "M_C_CPU1_SA_CS_N<2>")
	)
	(segment
		(start 77.700124 -258.85394)
		(end 69.13626 -262.401304)
		(width 0.18288)
		(layer "In4.Cu")
		(net "M_C_CPU1_SA_CS_N<2>")
	)
	(segment
		(start 34.24555 -268.291818)
		(end 32.301942 -268.291818)
		(width 0.18288)
		(layer "In4.Cu")
		(net "M_C_CPU1_SA_CS_N<2>")
	)
	(segment
		(start 32.301942 -268.291818)
		(end 31.876746 -267.866622)
		(width 0.18288)
		(layer "In4.Cu")
		(net "M_C_CPU1_SA_CS_N<2>")
	)
	(segment
		(start 46.152308 -267.442188)
		(end 45.126656 -267.442188)
		(width 0.18288)
		(layer "In4.Cu")
		(net "M_C_CPU1_SA_CS_N<2>")
	)
	(segment
		(start 46.152816 -267.44168)
		(end 46.152308 -267.442188)
		(width 0.18288)
		(layer "In4.Cu")
		(net "M_C_CPU1_SA_CS_N<2>")
	)
	(segment
		(start 63.887096 -265.544808)
		(end 62.93866 -266.493244)
		(width 0.18288)
		(layer "In4.Cu")
		(net "M_C_CPU1_SA_CS_N<2>")
	)
	(segment
		(start 85.103208 -258.04622)
		(end 84.434934 -258.04622)
		(width 0.088646)
		(layer "In4.Cu")
		(net "M_C_CPU1_SA_CS_N<2>")
	)
	(segment
		(start 44.177712 -268.391132)
		(end 40.583612 -268.391132)
		(width 0.18288)
		(layer "In4.Cu")
		(net "M_C_CPU1_SA_CS_N<2>")
	)
	(segment
		(start 62.411356 -267.44168)
		(end 46.152816 -267.44168)
		(width 0.18288)
		(layer "In4.Cu")
		(net "M_C_CPU1_SA_CS_N<2>")
	)
	(segment
		(start 90.88755 -259.127498)
		(end 90.87866 -259.122418)
		(width 0.088646)
		(layer "In4.Cu")
		(net "M_C_CPU1_SA_CS_N<2>")
	)
	(segment
		(start 45.126656 -267.442188)
		(end 44.177712 -268.391132)
		(width 0.18288)
		(layer "In4.Cu")
		(net "M_C_CPU1_SA_CS_N<2>")
	)
	(segment
		(start 93.11132 -259.616956)
		(end 93.045788 -259.551424)
		(width 0.088646)
		(layer "In4.Cu")
		(net "M_C_CPU1_SA_CS_N<2>")
	)
	(segment
		(start 64.566038 -265.544808)
		(end 63.887096 -265.544808)
		(width 0.18288)
		(layer "In4.Cu")
		(net "M_C_CPU1_SA_CS_N<2>")
	)
	(segment
		(start 40.583612 -268.391132)
		(end 39.832534 -269.14221)
		(width 0.18288)
		(layer "In4.Cu")
		(net "M_C_CPU1_SA_CS_N<2>")
	)
	(segment
		(start 84.434934 -258.04622)
		(end 83.99526 -258.04622)
		(width 0.18288)
		(layer "In4.Cu")
		(net "M_C_CPU1_SA_CS_N<2>")
	)
	(segment
		(start 66.620898 -264.916666)
		(end 65.19418 -264.916666)
		(width 0.18288)
		(layer "In4.Cu")
		(net "M_C_CPU1_SA_CS_N<2>")
	)
	(segment
		(start 83.18754 -258.85394)
		(end 77.700124 -258.85394)
		(width 0.18288)
		(layer "In4.Cu")
		(net "M_C_CPU1_SA_CS_N<2>")
	)
	(segment
		(start 85.294724 -258.237736)
		(end 85.103208 -258.04622)
		(width 0.088646)
		(layer "In4.Cu")
		(net "M_C_CPU1_SA_CS_N<2>")
	)
	(segment
		(start 85.435694 -258.237736)
		(end 85.294724 -258.237736)
		(width 0.088646)
		(layer "In4.Cu")
		(net "M_C_CPU1_SA_CS_N<2>")
	)
	(segment
		(start 92.216478 -259.118862)
		(end 92.201746 -259.127498)
		(width 0.088646)
		(layer "In4.Cu")
		(net "M_C_CPU1_SA_CS_N<2>")
	)
	(segment
		(start 83.99526 -258.04622)
		(end 83.18754 -258.85394)
		(width 0.18288)
		(layer "In4.Cu")
		(net "M_C_CPU1_SA_CS_N<2>")
	)
	(segment
		(start 69.13626 -262.401304)
		(end 66.620898 -264.916666)
		(width 0.18288)
		(layer "In4.Cu")
		(net "M_C_CPU1_SA_CS_N<2>")
	)
	(segment
		(start 93.423994 -259.616956)
		(end 93.11132 -259.616956)
		(width 0.088646)
		(layer "In4.Cu")
		(net "M_C_CPU1_SA_CS_N<2>")
	)
	(segment
		(start 90.700098 -258.80314)
		(end 90.700098 -258.788916)
		(width 0.088646)
		(layer "In4.Cu")
		(net "M_C_CPU1_SA_CS_N<2>")
	)
	(segment
		(start 89.862406 -258.307332)
		(end 89.851992 -258.313428)
		(width 0.088646)
		(layer "In4.Cu")
		(net "M_C_CPU1_SA_CS_N<2>")
	)
	(segment
		(start 65.19418 -264.916666)
		(end 64.566038 -265.544808)
		(width 0.18288)
		(layer "In4.Cu")
		(net "M_C_CPU1_SA_CS_N<2>")
	)
	(arc
		(start 91.82735 -259.127498)
		(mid 91.544648 -259.051722)
		(end 91.261946 -259.127498)
		(width 0.088646)
		(layer "In4.Cu")
		(net "M_C_CPU1_SA_CS_N<2>")
	)
	(arc
		(start 89.851992 -258.313428)
		(mid 89.664794 -258.363571)
		(end 89.477596 -258.313428)
		(width 0.088646)
		(layer "In4.Cu")
		(net "M_C_CPU1_SA_CS_N<2>")
	)
	(arc
		(start 92.201746 -259.127498)
		(mid 92.014548 -259.177641)
		(end 91.82735 -259.127498)
		(width 0.088646)
		(layer "In4.Cu")
		(net "M_C_CPU1_SA_CS_N<2>")
	)
	(arc
		(start 87.972392 -258.313428)
		(mid 87.785194 -258.363571)
		(end 87.597996 -258.313428)
		(width 0.088646)
		(layer "In4.Cu")
		(net "M_C_CPU1_SA_CS_N<2>")
	)
	(arc
		(start 86.658196 -258.313428)
		(mid 86.375494 -258.237686)
		(end 86.092792 -258.313428)
		(width 0.088646)
		(layer "In4.Cu")
		(net "M_C_CPU1_SA_CS_N<2>")
	)
	(arc
		(start 88.912192 -258.313428)
		(mid 88.724994 -258.363571)
		(end 88.537796 -258.313428)
		(width 0.088646)
		(layer "In4.Cu")
		(net "M_C_CPU1_SA_CS_N<2>")
	)
	(arc
		(start 88.537796 -258.313428)
		(mid 88.255094 -258.237686)
		(end 87.972392 -258.313428)
		(width 0.088646)
		(layer "In4.Cu")
		(net "M_C_CPU1_SA_CS_N<2>")
	)
	(arc
		(start 87.032592 -258.313428)
		(mid 86.845394 -258.363571)
		(end 86.658196 -258.313428)
		(width 0.088646)
		(layer "In4.Cu")
		(net "M_C_CPU1_SA_CS_N<2>")
	)
	(arc
		(start 89.477596 -258.313428)
		(mid 89.194894 -258.237686)
		(end 88.912192 -258.313428)
		(width 0.088646)
		(layer "In4.Cu")
		(net "M_C_CPU1_SA_CS_N<2>")
	)
	(arc
		(start 85.718396 -258.313428)
		(mid 85.58203 -258.25695)
		(end 85.435694 -258.237736)
		(width 0.088646)
		(layer "In4.Cu")
		(net "M_C_CPU1_SA_CS_N<2>")
	)
	(arc
		(start 90.41765 -258.313428)
		(mid 90.140837 -258.237592)
		(end 89.862406 -258.307332)
		(width 0.088646)
		(layer "In4.Cu")
		(net "M_C_CPU1_SA_CS_N<2>")
	)
	(arc
		(start 91.261946 -259.127498)
		(mid 91.074748 -259.177641)
		(end 90.88755 -259.127498)
		(width 0.088646)
		(layer "In4.Cu")
		(net "M_C_CPU1_SA_CS_N<2>")
	)
	(arc
		(start 87.597996 -258.313428)
		(mid 87.315294 -258.237686)
		(end 87.032592 -258.313428)
		(width 0.088646)
		(layer "In4.Cu")
		(net "M_C_CPU1_SA_CS_N<2>")
	)
	(arc
		(start 90.700098 -258.788916)
		(mid 90.620957 -258.514293)
		(end 90.41765 -258.313428)
		(width 0.088646)
		(layer "In4.Cu")
		(net "M_C_CPU1_SA_CS_N<2>")
	)
	(arc
		(start 92.76715 -259.127498)
		(mid 92.492951 -259.051663)
		(end 92.216478 -259.118862)
		(width 0.088646)
		(layer "In4.Cu")
		(net "M_C_CPU1_SA_CS_N<2>")
	)
	(arc
		(start 93.045788 -259.551424)
		(mid 92.9567 -259.306439)
		(end 92.76715 -259.127498)
		(width 0.088646)
		(layer "In4.Cu")
		(net "M_C_CPU1_SA_CS_N<2>")
	)
	(arc
		(start 86.092792 -258.313428)
		(mid 85.905594 -258.363571)
		(end 85.718396 -258.313428)
		(width 0.088646)
		(layer "In4.Cu")
		(net "M_C_CPU1_SA_CS_N<2>")
	)
	(arc
		(start 90.87866 -259.122418)
		(mid 90.747746 -258.986058)
		(end 90.700098 -258.80314)
		(width 0.088646)
		(layer "In4.Cu")
		(net "M_C_CPU1_SA_CS_N<2>")
	)
	(segment
		(start 92.014294 -258.2672)
		(end 92.014548 -258.267454)
		(width 0.20066)
		(layer "F.Cu")
		(net "M_C_CPU1_SA_CS_N<1>")
	)
	(segment
		(start 92.014548 -258.267454)
		(end 92.014548 -258.80314)
		(width 0.20066)
		(layer "F.Cu")
		(net "M_C_CPU1_SA_CS_N<1>")
	)
	(segment
		(start 27.328114 -267.016738)
		(end 28.433014 -267.016738)
		(width 0.20066)
		(layer "F.Cu")
		(net "M_C_CPU1_SA_CS_N<1>")
	)
	(segment
		(start 60.629546 -265.299952)
		(end 60.446666 -265.482832)
		(width 0.18288)
		(layer "In4.Cu")
		(net "M_C_CPU1_SA_CS_N<1>")
	)
	(segment
		(start 40.681402 -267.443458)
		(end 39.833042 -268.291818)
		(width 0.18288)
		(layer "In4.Cu")
		(net "M_C_CPU1_SA_CS_N<1>")
	)
	(segment
		(start 60.446666 -266.408916)
		(end 60.263786 -266.591796)
		(width 0.18288)
		(layer "In4.Cu")
		(net "M_C_CPU1_SA_CS_N<1>")
	)
	(segment
		(start 62.047882 -266.591796)
		(end 61.320426 -266.591796)
		(width 0.18288)
		(layer "In4.Cu")
		(net "M_C_CPU1_SA_CS_N<1>")
	)
	(segment
		(start 66.697098 -263.961626)
		(end 65.310766 -263.961626)
		(width 0.18288)
		(layer "In4.Cu")
		(net "M_C_CPU1_SA_CS_N<1>")
	)
	(segment
		(start 91.502992 -258.61772)
		(end 91.261946 -258.478782)
		(width 0.088646)
		(layer "In4.Cu")
		(net "M_C_CPU1_SA_CS_N<1>")
	)
	(segment
		(start 33.819084 -267.016738)
		(end 32.928814 -267.016738)
		(width 0.18288)
		(layer "In4.Cu")
		(net "M_C_CPU1_SA_CS_N<1>")
	)
	(segment
		(start 84.435442 -257.71094)
		(end 83.812888 -257.71094)
		(width 0.18288)
		(layer "In4.Cu")
		(net "M_C_CPU1_SA_CS_N<1>")
	)
	(segment
		(start 92.014548 -258.80314)
		(end 92.006674 -258.795266)
		(width 0.088646)
		(layer "In4.Cu")
		(net "M_C_CPU1_SA_CS_N<1>")
	)
	(segment
		(start 63.640716 -264.998962)
		(end 62.047882 -266.591796)
		(width 0.18288)
		(layer "In4.Cu")
		(net "M_C_CPU1_SA_CS_N<1>")
	)
	(segment
		(start 35.094164 -268.291818)
		(end 33.819084 -267.016738)
		(width 0.18288)
		(layer "In4.Cu")
		(net "M_C_CPU1_SA_CS_N<1>")
	)
	(segment
		(start 83.812888 -257.71094)
		(end 83.005168 -258.51866)
		(width 0.18288)
		(layer "In4.Cu")
		(net "M_C_CPU1_SA_CS_N<1>")
	)
	(segment
		(start 68.59778 -262.060944)
		(end 66.697098 -263.961626)
		(width 0.18288)
		(layer "In4.Cu")
		(net "M_C_CPU1_SA_CS_N<1>")
	)
	(segment
		(start 44.562014 -266.591796)
		(end 43.710352 -267.443458)
		(width 0.18288)
		(layer "In4.Cu")
		(net "M_C_CPU1_SA_CS_N<1>")
	)
	(segment
		(start 61.320426 -266.591796)
		(end 61.137546 -266.408916)
		(width 0.18288)
		(layer "In4.Cu")
		(net "M_C_CPU1_SA_CS_N<1>")
	)
	(segment
		(start 64.27343 -264.998962)
		(end 63.640716 -264.998962)
		(width 0.18288)
		(layer "In4.Cu")
		(net "M_C_CPU1_SA_CS_N<1>")
	)
	(segment
		(start 89.862406 -257.670808)
		(end 89.851992 -257.664712)
		(width 0.088646)
		(layer "In4.Cu")
		(net "M_C_CPU1_SA_CS_N<1>")
	)
	(segment
		(start 60.263786 -266.591796)
		(end 44.562014 -266.591796)
		(width 0.18288)
		(layer "In4.Cu")
		(net "M_C_CPU1_SA_CS_N<1>")
	)
	(segment
		(start 85.435694 -257.740404)
		(end 84.903056 -257.740404)
		(width 0.088646)
		(layer "In4.Cu")
		(net "M_C_CPU1_SA_CS_N<1>")
	)
	(segment
		(start 65.310766 -263.961626)
		(end 64.27343 -264.998962)
		(width 0.18288)
		(layer "In4.Cu")
		(net "M_C_CPU1_SA_CS_N<1>")
	)
	(segment
		(start 61.137546 -266.408916)
		(end 61.137546 -265.482832)
		(width 0.18288)
		(layer "In4.Cu")
		(net "M_C_CPU1_SA_CS_N<1>")
	)
	(segment
		(start 61.137546 -265.482832)
		(end 60.954666 -265.299952)
		(width 0.18288)
		(layer "In4.Cu")
		(net "M_C_CPU1_SA_CS_N<1>")
	)
	(segment
		(start 77.147928 -258.51866)
		(end 68.59778 -262.060944)
		(width 0.18288)
		(layer "In4.Cu")
		(net "M_C_CPU1_SA_CS_N<1>")
	)
	(segment
		(start 84.873592 -257.71094)
		(end 84.435442 -257.71094)
		(width 0.088646)
		(layer "In4.Cu")
		(net "M_C_CPU1_SA_CS_N<1>")
	)
	(segment
		(start 60.954666 -265.299952)
		(end 60.629546 -265.299952)
		(width 0.18288)
		(layer "In4.Cu")
		(net "M_C_CPU1_SA_CS_N<1>")
	)
	(segment
		(start 84.903056 -257.740404)
		(end 84.873592 -257.71094)
		(width 0.088646)
		(layer "In4.Cu")
		(net "M_C_CPU1_SA_CS_N<1>")
	)
	(segment
		(start 32.50692 -266.594844)
		(end 28.854908 -266.594844)
		(width 0.18288)
		(layer "In4.Cu")
		(net "M_C_CPU1_SA_CS_N<1>")
	)
	(segment
		(start 43.710352 -267.443458)
		(end 40.681402 -267.443458)
		(width 0.18288)
		(layer "In4.Cu")
		(net "M_C_CPU1_SA_CS_N<1>")
	)
	(segment
		(start 32.928814 -267.016738)
		(end 32.50692 -266.594844)
		(width 0.18288)
		(layer "In4.Cu")
		(net "M_C_CPU1_SA_CS_N<1>")
	)
	(segment
		(start 90.979244 -258.003294)
		(end 90.979244 -257.980434)
		(width 0.088646)
		(layer "In4.Cu")
		(net "M_C_CPU1_SA_CS_N<1>")
	)
	(segment
		(start 60.446666 -265.482832)
		(end 60.446666 -266.408916)
		(width 0.18288)
		(layer "In4.Cu")
		(net "M_C_CPU1_SA_CS_N<1>")
	)
	(segment
		(start 28.854908 -266.594844)
		(end 28.433014 -267.016738)
		(width 0.18288)
		(layer "In4.Cu")
		(net "M_C_CPU1_SA_CS_N<1>")
	)
	(segment
		(start 83.005168 -258.51866)
		(end 77.147928 -258.51866)
		(width 0.18288)
		(layer "In4.Cu")
		(net "M_C_CPU1_SA_CS_N<1>")
	)
	(segment
		(start 39.833042 -268.291818)
		(end 35.094164 -268.291818)
		(width 0.18288)
		(layer "In4.Cu")
		(net "M_C_CPU1_SA_CS_N<1>")
	)
	(arc
		(start 89.851992 -257.664712)
		(mid 89.664794 -257.614569)
		(end 89.477596 -257.664712)
		(width 0.088646)
		(layer "In4.Cu")
		(net "M_C_CPU1_SA_CS_N<1>")
	)
	(arc
		(start 86.658196 -257.664712)
		(mid 86.375494 -257.740488)
		(end 86.092792 -257.664712)
		(width 0.088646)
		(layer "In4.Cu")
		(net "M_C_CPU1_SA_CS_N<1>")
	)
	(arc
		(start 90.792046 -257.664712)
		(mid 90.604848 -257.614569)
		(end 90.41765 -257.664712)
		(width 0.088646)
		(layer "In4.Cu")
		(net "M_C_CPU1_SA_CS_N<1>")
	)
	(arc
		(start 87.597996 -257.664712)
		(mid 87.315294 -257.740488)
		(end 87.032592 -257.664712)
		(width 0.088646)
		(layer "In4.Cu")
		(net "M_C_CPU1_SA_CS_N<1>")
	)
	(arc
		(start 87.032592 -257.664712)
		(mid 86.845394 -257.614569)
		(end 86.658196 -257.664712)
		(width 0.088646)
		(layer "In4.Cu")
		(net "M_C_CPU1_SA_CS_N<1>")
	)
	(arc
		(start 88.912192 -257.664712)
		(mid 88.724994 -257.614569)
		(end 88.537796 -257.664712)
		(width 0.088646)
		(layer "In4.Cu")
		(net "M_C_CPU1_SA_CS_N<1>")
	)
	(arc
		(start 85.718396 -257.664712)
		(mid 85.582027 -257.721154)
		(end 85.435694 -257.740404)
		(width 0.088646)
		(layer "In4.Cu")
		(net "M_C_CPU1_SA_CS_N<1>")
	)
	(arc
		(start 91.261946 -258.478782)
		(mid 91.058465 -258.277978)
		(end 90.979244 -258.003294)
		(width 0.088646)
		(layer "In4.Cu")
		(net "M_C_CPU1_SA_CS_N<1>")
	)
	(arc
		(start 86.092792 -257.664712)
		(mid 85.905594 -257.614569)
		(end 85.718396 -257.664712)
		(width 0.088646)
		(layer "In4.Cu")
		(net "M_C_CPU1_SA_CS_N<1>")
	)
	(arc
		(start 90.979244 -257.980434)
		(mid 90.926974 -257.798069)
		(end 90.792046 -257.664712)
		(width 0.088646)
		(layer "In4.Cu")
		(net "M_C_CPU1_SA_CS_N<1>")
	)
	(arc
		(start 88.537796 -257.664712)
		(mid 88.255094 -257.740488)
		(end 87.972392 -257.664712)
		(width 0.088646)
		(layer "In4.Cu")
		(net "M_C_CPU1_SA_CS_N<1>")
	)
	(arc
		(start 87.972392 -257.664712)
		(mid 87.785194 -257.614569)
		(end 87.597996 -257.664712)
		(width 0.088646)
		(layer "In4.Cu")
		(net "M_C_CPU1_SA_CS_N<1>")
	)
	(arc
		(start 89.477596 -257.664712)
		(mid 89.194894 -257.740488)
		(end 88.912192 -257.664712)
		(width 0.088646)
		(layer "In4.Cu")
		(net "M_C_CPU1_SA_CS_N<1>")
	)
	(arc
		(start 91.716098 -258.67487)
		(mid 91.605795 -258.660291)
		(end 91.502992 -258.61772)
		(width 0.088646)
		(layer "In4.Cu")
		(net "M_C_CPU1_SA_CS_N<1>")
	)
	(arc
		(start 90.41765 -257.664712)
		(mid 90.140837 -257.740582)
		(end 89.862406 -257.670808)
		(width 0.088646)
		(layer "In4.Cu")
		(net "M_C_CPU1_SA_CS_N<1>")
	)
	(arc
		(start 92.006674 -258.795266)
		(mid 91.873357 -258.706186)
		(end 91.716098 -258.67487)
		(width 0.088646)
		(layer "In4.Cu")
		(net "M_C_CPU1_SA_CS_N<1>")
	)
	(segment
		(start 23.228046 -267.866622)
		(end 24.332946 -267.866622)
		(width 0.20066)
		(layer "F.Cu")
		(net "M_C_CPU1_SA_CS_N<0>")
	)
	(segment
		(start 92.484448 -259.616702)
		(end 92.484194 -259.616956)
		(width 0.20066)
		(layer "F.Cu")
		(net "M_C_CPU1_SA_CS_N<0>")
	)
	(segment
		(start 92.484448 -259.081016)
		(end 92.484448 -259.616702)
		(width 0.20066)
		(layer "F.Cu")
		(net "M_C_CPU1_SA_CS_N<0>")
	)
	(segment
		(start 92.484194 -259.616956)
		(end 92.796868 -259.616956)
		(width 0.088646)
		(layer "In4.Cu")
		(net "M_C_CPU1_SA_CS_N<0>")
	)
	(segment
		(start 69.534786 -262.804656)
		(end 66.71945 -265.619992)
		(width 0.18288)
		(layer "In4.Cu")
		(net "M_C_CPU1_SA_CS_N<0>")
	)
	(segment
		(start 39.948358 -269.993618)
		(end 35.059874 -269.993618)
		(width 0.18288)
		(layer "In4.Cu")
		(net "M_C_CPU1_SA_CS_N<0>")
	)
	(segment
		(start 43.882564 -268.998954)
		(end 40.943022 -268.998954)
		(width 0.18288)
		(layer "In4.Cu")
		(net "M_C_CPU1_SA_CS_N<0>")
	)
	(segment
		(start 65.324736 -265.619992)
		(end 62.65291 -268.291818)
		(width 0.18288)
		(layer "In4.Cu")
		(net "M_C_CPU1_SA_CS_N<0>")
	)
	(segment
		(start 90.330782 -258.483862)
		(end 90.321892 -258.478782)
		(width 0.088646)
		(layer "In4.Cu")
		(net "M_C_CPU1_SA_CS_N<0>")
	)
	(segment
		(start 84.158328 -258.3815)
		(end 83.350608 -259.18922)
		(width 0.18288)
		(layer "In4.Cu")
		(net "M_C_CPU1_SA_CS_N<0>")
	)
	(segment
		(start 34.207958 -269.141702)
		(end 25.608026 -269.141702)
		(width 0.18288)
		(layer "In4.Cu")
		(net "M_C_CPU1_SA_CS_N<0>")
	)
	(segment
		(start 45.860462 -268.291818)
		(end 44.905422 -269.246858)
		(width 0.18288)
		(layer "In4.Cu")
		(net "M_C_CPU1_SA_CS_N<0>")
	)
	(segment
		(start 85.110828 -258.427982)
		(end 85.064346 -258.3815)
		(width 0.088646)
		(layer "In4.Cu")
		(net "M_C_CPU1_SA_CS_N<0>")
	)
	(segment
		(start 44.130468 -269.246858)
		(end 43.882564 -268.998954)
		(width 0.18288)
		(layer "In4.Cu")
		(net "M_C_CPU1_SA_CS_N<0>")
	)
	(segment
		(start 78.260194 -259.18922)
		(end 69.534786 -262.804656)
		(width 0.18288)
		(layer "In4.Cu")
		(net "M_C_CPU1_SA_CS_N<0>")
	)
	(segment
		(start 85.064346 -258.3815)
		(end 84.434934 -258.3815)
		(width 0.088646)
		(layer "In4.Cu")
		(net "M_C_CPU1_SA_CS_N<0>")
	)
	(segment
		(start 85.435694 -258.427982)
		(end 85.110828 -258.427982)
		(width 0.088646)
		(layer "In4.Cu")
		(net "M_C_CPU1_SA_CS_N<0>")
	)
	(segment
		(start 40.943022 -268.998954)
		(end 39.948358 -269.993618)
		(width 0.18288)
		(layer "In4.Cu")
		(net "M_C_CPU1_SA_CS_N<0>")
	)
	(segment
		(start 90.791792 -259.292598)
		(end 90.785696 -259.289042)
		(width 0.088646)
		(layer "In4.Cu")
		(net "M_C_CPU1_SA_CS_N<0>")
	)
	(segment
		(start 25.608026 -269.141702)
		(end 24.332946 -267.866622)
		(width 0.18288)
		(layer "In4.Cu")
		(net "M_C_CPU1_SA_CS_N<0>")
	)
	(segment
		(start 44.905422 -269.246858)
		(end 44.130468 -269.246858)
		(width 0.18288)
		(layer "In4.Cu")
		(net "M_C_CPU1_SA_CS_N<0>")
	)
	(segment
		(start 83.350608 -259.18922)
		(end 78.260194 -259.18922)
		(width 0.18288)
		(layer "In4.Cu")
		(net "M_C_CPU1_SA_CS_N<0>")
	)
	(segment
		(start 84.434934 -258.3815)
		(end 84.158328 -258.3815)
		(width 0.18288)
		(layer "In4.Cu")
		(net "M_C_CPU1_SA_CS_N<0>")
	)
	(segment
		(start 92.680282 -259.297678)
		(end 92.671392 -259.292598)
		(width 0.088646)
		(layer "In4.Cu")
		(net "M_C_CPU1_SA_CS_N<0>")
	)
	(segment
		(start 91.35745 -259.292598)
		(end 91.347036 -259.298694)
		(width 0.088646)
		(layer "In4.Cu")
		(net "M_C_CPU1_SA_CS_N<0>")
	)
	(segment
		(start 35.059874 -269.993618)
		(end 34.207958 -269.141702)
		(width 0.18288)
		(layer "In4.Cu")
		(net "M_C_CPU1_SA_CS_N<0>")
	)
	(segment
		(start 62.65291 -268.291818)
		(end 45.860462 -268.291818)
		(width 0.18288)
		(layer "In4.Cu")
		(net "M_C_CPU1_SA_CS_N<0>")
	)
	(segment
		(start 92.296996 -259.292598)
		(end 92.286582 -259.298694)
		(width 0.088646)
		(layer "In4.Cu")
		(net "M_C_CPU1_SA_CS_N<0>")
	)
	(segment
		(start 92.796868 -259.616956)
		(end 92.854272 -259.559552)
		(width 0.088646)
		(layer "In4.Cu")
		(net "M_C_CPU1_SA_CS_N<0>")
	)
	(segment
		(start 66.71945 -265.619992)
		(end 65.324736 -265.619992)
		(width 0.18288)
		(layer "In4.Cu")
		(net "M_C_CPU1_SA_CS_N<0>")
	)
	(arc
		(start 85.622892 -258.478782)
		(mid 85.532636 -258.44106)
		(end 85.435694 -258.427982)
		(width 0.088646)
		(layer "In4.Cu")
		(net "M_C_CPU1_SA_CS_N<0>")
	)
	(arc
		(start 87.502492 -258.478782)
		(mid 87.315294 -258.428639)
		(end 87.128096 -258.478782)
		(width 0.088646)
		(layer "In4.Cu")
		(net "M_C_CPU1_SA_CS_N<0>")
	)
	(arc
		(start 92.671392 -259.292598)
		(mid 92.484194 -259.242455)
		(end 92.296996 -259.292598)
		(width 0.088646)
		(layer "In4.Cu")
		(net "M_C_CPU1_SA_CS_N<0>")
	)
	(arc
		(start 89.007696 -258.478782)
		(mid 88.724994 -258.554524)
		(end 88.442292 -258.478782)
		(width 0.088646)
		(layer "In4.Cu")
		(net "M_C_CPU1_SA_CS_N<0>")
	)
	(arc
		(start 92.854272 -259.559552)
		(mid 92.796116 -259.409439)
		(end 92.680282 -259.297678)
		(width 0.088646)
		(layer "In4.Cu")
		(net "M_C_CPU1_SA_CS_N<0>")
	)
	(arc
		(start 88.067896 -258.478782)
		(mid 87.785194 -258.554524)
		(end 87.502492 -258.478782)
		(width 0.088646)
		(layer "In4.Cu")
		(net "M_C_CPU1_SA_CS_N<0>")
	)
	(arc
		(start 91.347036 -259.298694)
		(mid 91.068604 -259.36854)
		(end 90.791792 -259.292598)
		(width 0.088646)
		(layer "In4.Cu")
		(net "M_C_CPU1_SA_CS_N<0>")
	)
	(arc
		(start 86.562692 -258.478782)
		(mid 86.375494 -258.428639)
		(end 86.188296 -258.478782)
		(width 0.088646)
		(layer "In4.Cu")
		(net "M_C_CPU1_SA_CS_N<0>")
	)
	(arc
		(start 87.128096 -258.478782)
		(mid 86.845394 -258.554524)
		(end 86.562692 -258.478782)
		(width 0.088646)
		(layer "In4.Cu")
		(net "M_C_CPU1_SA_CS_N<0>")
	)
	(arc
		(start 86.188296 -258.478782)
		(mid 85.905594 -258.554524)
		(end 85.622892 -258.478782)
		(width 0.088646)
		(layer "In4.Cu")
		(net "M_C_CPU1_SA_CS_N<0>")
	)
	(arc
		(start 89.947496 -258.478782)
		(mid 89.664794 -258.554524)
		(end 89.382092 -258.478782)
		(width 0.088646)
		(layer "In4.Cu")
		(net "M_C_CPU1_SA_CS_N<0>")
	)
	(arc
		(start 90.509344 -258.80314)
		(mid 90.461665 -258.62024)
		(end 90.330782 -258.483862)
		(width 0.088646)
		(layer "In4.Cu")
		(net "M_C_CPU1_SA_CS_N<0>")
	)
	(arc
		(start 92.286582 -259.298694)
		(mid 92.008404 -259.368417)
		(end 91.731846 -259.292598)
		(width 0.088646)
		(layer "In4.Cu")
		(net "M_C_CPU1_SA_CS_N<0>")
	)
	(arc
		(start 89.382092 -258.478782)
		(mid 89.194894 -258.428639)
		(end 89.007696 -258.478782)
		(width 0.088646)
		(layer "In4.Cu")
		(net "M_C_CPU1_SA_CS_N<0>")
	)
	(arc
		(start 88.442292 -258.478782)
		(mid 88.255094 -258.428639)
		(end 88.067896 -258.478782)
		(width 0.088646)
		(layer "In4.Cu")
		(net "M_C_CPU1_SA_CS_N<0>")
	)
	(arc
		(start 91.731846 -259.292598)
		(mid 91.544648 -259.242455)
		(end 91.35745 -259.292598)
		(width 0.088646)
		(layer "In4.Cu")
		(net "M_C_CPU1_SA_CS_N<0>")
	)
	(arc
		(start 90.321892 -258.478782)
		(mid 90.134694 -258.428639)
		(end 89.947496 -258.478782)
		(width 0.088646)
		(layer "In4.Cu")
		(net "M_C_CPU1_SA_CS_N<0>")
	)
	(arc
		(start 90.785696 -259.289042)
		(mid 90.583283 -259.082629)
		(end 90.509344 -258.80314)
		(width 0.088646)
		(layer "In4.Cu")
		(net "M_C_CPU1_SA_CS_N<0>")
	)
	(segment
		(start 32.666178 -270.641064)
		(end 32.666178 -270.478758)
		(width 0.20066)
		(layer "F.Cu")
		(net "M_C_CPU1_SA_CB<7>")
	)
	(segment
		(start 29.151326 -270.542766)
		(end 29.151326 -270.69923)
		(width 0.20066)
		(layer "F.Cu")
		(net "M_C_CPU1_SA_CB<7>")
	)
	(segment
		(start 33.422844 -270.522446)
		(end 33.950148 -270.522446)
		(width 0.20066)
		(layer "F.Cu")
		(net "M_C_CPU1_SA_CB<7>")
	)
	(segment
		(start 96.713294 -258.2672)
		(end 96.713294 -258.802886)
		(width 0.20066)
		(layer "F.Cu")
		(net "M_C_CPU1_SA_CB<7>")
	)
	(segment
		(start 34.055812 -270.416782)
		(end 34.871914 -270.416782)
		(width 0.20066)
		(layer "F.Cu")
		(net "M_C_CPU1_SA_CB<7>")
	)
	(segment
		(start 33.178496 -270.278098)
		(end 33.422844 -270.522446)
		(width 0.20066)
		(layer "F.Cu")
		(net "M_C_CPU1_SA_CB<7>")
	)
	(segment
		(start 32.666178 -270.478758)
		(end 32.866838 -270.278098)
		(width 0.20066)
		(layer "F.Cu")
		(net "M_C_CPU1_SA_CB<7>")
	)
	(segment
		(start 32.465518 -270.841724)
		(end 32.666178 -270.641064)
		(width 0.20066)
		(layer "F.Cu")
		(net "M_C_CPU1_SA_CB<7>")
	)
	(segment
		(start 29.151326 -270.69923)
		(end 29.29382 -270.841724)
		(width 0.20066)
		(layer "F.Cu")
		(net "M_C_CPU1_SA_CB<7>")
	)
	(segment
		(start 33.950148 -270.522446)
		(end 34.055812 -270.416782)
		(width 0.20066)
		(layer "F.Cu")
		(net "M_C_CPU1_SA_CB<7>")
	)
	(segment
		(start 29.025342 -270.416782)
		(end 29.151326 -270.542766)
		(width 0.20066)
		(layer "F.Cu")
		(net "M_C_CPU1_SA_CB<7>")
	)
	(segment
		(start 32.028892 -270.841724)
		(end 32.465518 -270.841724)
		(width 0.20066)
		(layer "F.Cu")
		(net "M_C_CPU1_SA_CB<7>")
	)
	(segment
		(start 29.661866 -270.841724)
		(end 31.972758 -270.841724)
		(width 0.1016)
		(layer "F.Cu")
		(net "M_C_CPU1_SA_CB<7>")
	)
	(segment
		(start 96.713294 -258.802886)
		(end 96.713548 -258.80314)
		(width 0.20066)
		(layer "F.Cu")
		(net "M_C_CPU1_SA_CB<7>")
	)
	(segment
		(start 29.29382 -270.841724)
		(end 29.516324 -270.841724)
		(width 0.20066)
		(layer "F.Cu")
		(net "M_C_CPU1_SA_CB<7>")
	)
	(segment
		(start 31.972758 -270.841724)
		(end 32.028892 -270.841724)
		(width 0.101854)
		(layer "F.Cu")
		(net "M_C_CPU1_SA_CB<7>")
	)
	(segment
		(start 29.516324 -270.841724)
		(end 29.661866 -270.841724)
		(width 0.101854)
		(layer "F.Cu")
		(net "M_C_CPU1_SA_CB<7>")
	)
	(segment
		(start 27.328114 -270.416782)
		(end 29.025342 -270.416782)
		(width 0.20066)
		(layer "F.Cu")
		(net "M_C_CPU1_SA_CB<7>")
	)
	(segment
		(start 32.866838 -270.278098)
		(end 33.178496 -270.278098)
		(width 0.20066)
		(layer "F.Cu")
		(net "M_C_CPU1_SA_CB<7>")
	)
	(segment
		(start 35.976814 -270.416782)
		(end 34.871914 -270.416782)
		(width 0.20066)
		(layer "F.Cu")
		(net "M_C_CPU1_SA_CB<7>")
	)
	(segment
		(start 59.200542 -262.343646)
		(end 55.961534 -262.343646)
		(width 0.18288)
		(layer "In6.Cu")
		(net "M_C_CPU1_SA_CB<7>")
	)
	(segment
		(start 94.09176 -258.484878)
		(end 94.081346 -258.478782)
		(width 0.088646)
		(layer "In6.Cu")
		(net "M_C_CPU1_SA_CB<7>")
	)
	(segment
		(start 40.595042 -267.334492)
		(end 40.595042 -267.593318)
		(width 0.18288)
		(layer "In6.Cu")
		(net "M_C_CPU1_SA_CB<7>")
	)
	(segment
		(start 77.921358 -260.54304)
		(end 63.760604 -260.54304)
		(width 0.18288)
		(layer "In6.Cu")
		(net "M_C_CPU1_SA_CB<7>")
	)
	(segment
		(start 39.069264 -268.288516)
		(end 37.579554 -269.778226)
		(width 0.18288)
		(layer "In6.Cu")
		(net "M_C_CPU1_SA_CB<7>")
	)
	(segment
		(start 47.601378 -264.040874)
		(end 45.137578 -264.040874)
		(width 0.18288)
		(layer "In6.Cu")
		(net "M_C_CPU1_SA_CB<7>")
	)
	(segment
		(start 40.092376 -266.113006)
		(end 39.862252 -266.34313)
		(width 0.18288)
		(layer "In6.Cu")
		(net "M_C_CPU1_SA_CB<7>")
	)
	(segment
		(start 83.088734 -259.234178)
		(end 81.081372 -259.234178)
		(width 0.18288)
		(layer "In6.Cu")
		(net "M_C_CPU1_SA_CB<7>")
	)
	(segment
		(start 91.276678 -258.487418)
		(end 91.261946 -258.478782)
		(width 0.088646)
		(layer "In6.Cu")
		(net "M_C_CPU1_SA_CB<7>")
	)
	(segment
		(start 96.400874 -258.80314)
		(end 96.335088 -258.868926)
		(width 0.088646)
		(layer "In6.Cu")
		(net "M_C_CPU1_SA_CB<7>")
	)
	(segment
		(start 59.520582 -263.008872)
		(end 59.360562 -262.848852)
		(width 0.18288)
		(layer "In6.Cu")
		(net "M_C_CPU1_SA_CB<7>")
	)
	(segment
		(start 52.836826 -262.67156)
		(end 52.653946 -262.48868)
		(width 0.18288)
		(layer "In6.Cu")
		(net "M_C_CPU1_SA_CB<7>")
	)
	(segment
		(start 63.760604 -260.54304)
		(end 62.935612 -261.368032)
		(width 0.18288)
		(layer "In6.Cu")
		(net "M_C_CPU1_SA_CB<7>")
	)
	(segment
		(start 51.963066 -263.19099)
		(end 48.451262 -263.19099)
		(width 0.18288)
		(layer "In6.Cu")
		(net "M_C_CPU1_SA_CB<7>")
	)
	(segment
		(start 95.490792 -259.292598)
		(end 95.484696 -259.289042)
		(width 0.088646)
		(layer "In6.Cu")
		(net "M_C_CPU1_SA_CB<7>")
	)
	(segment
		(start 96.713548 -258.80314)
		(end 96.400874 -258.80314)
		(width 0.088646)
		(layer "In6.Cu")
		(net "M_C_CPU1_SA_CB<7>")
	)
	(segment
		(start 83.34629 -259.234178)
		(end 83.088734 -259.234178)
		(width 0.088646)
		(layer "In6.Cu")
		(net "M_C_CPU1_SA_CB<7>")
	)
	(segment
		(start 96.056196 -259.292598)
		(end 96.041464 -259.301234)
		(width 0.088646)
		(layer "In6.Cu")
		(net "M_C_CPU1_SA_CB<7>")
	)
	(segment
		(start 59.893962 -263.008872)
		(end 59.520582 -263.008872)
		(width 0.18288)
		(layer "In6.Cu")
		(net "M_C_CPU1_SA_CB<7>")
	)
	(segment
		(start 59.360562 -262.503666)
		(end 59.200542 -262.343646)
		(width 0.18288)
		(layer "In6.Cu")
		(net "M_C_CPU1_SA_CB<7>")
	)
	(segment
		(start 52.328826 -262.48868)
		(end 52.145946 -262.67156)
		(width 0.18288)
		(layer "In6.Cu")
		(net "M_C_CPU1_SA_CB<7>")
	)
	(segment
		(start 53.710586 -262.48868)
		(end 53.527706 -262.67156)
		(width 0.18288)
		(layer "In6.Cu")
		(net "M_C_CPU1_SA_CB<7>")
	)
	(segment
		(start 41.083992 -266.84605)
		(end 40.350948 -266.113006)
		(width 0.18288)
		(layer "In6.Cu")
		(net "M_C_CPU1_SA_CB<7>")
	)
	(segment
		(start 60.214002 -262.343646)
		(end 60.053982 -262.503666)
		(width 0.18288)
		(layer "In6.Cu")
		(net "M_C_CPU1_SA_CB<7>")
	)
	(segment
		(start 52.145946 -262.67156)
		(end 52.145946 -263.00811)
		(width 0.18288)
		(layer "In6.Cu")
		(net "M_C_CPU1_SA_CB<7>")
	)
	(segment
		(start 52.145946 -263.00811)
		(end 51.963066 -263.19099)
		(width 0.18288)
		(layer "In6.Cu")
		(net "M_C_CPU1_SA_CB<7>")
	)
	(segment
		(start 59.360562 -262.848852)
		(end 59.360562 -262.503666)
		(width 0.18288)
		(layer "In6.Cu")
		(net "M_C_CPU1_SA_CB<7>")
	)
	(segment
		(start 53.019706 -263.19099)
		(end 52.836826 -263.00811)
		(width 0.18288)
		(layer "In6.Cu")
		(net "M_C_CPU1_SA_CB<7>")
	)
	(segment
		(start 95.029782 -258.483862)
		(end 95.020892 -258.478782)
		(width 0.088646)
		(layer "In6.Cu")
		(net "M_C_CPU1_SA_CB<7>")
	)
	(segment
		(start 39.862252 -266.34313)
		(end 39.862252 -266.601702)
		(width 0.18288)
		(layer "In6.Cu")
		(net "M_C_CPU1_SA_CB<7>")
	)
	(segment
		(start 53.344826 -263.19099)
		(end 53.019706 -263.19099)
		(width 0.18288)
		(layer "In6.Cu")
		(net "M_C_CPU1_SA_CB<7>")
	)
	(segment
		(start 55.11419 -263.19099)
		(end 54.401466 -263.19099)
		(width 0.18288)
		(layer "In6.Cu")
		(net "M_C_CPU1_SA_CB<7>")
	)
	(segment
		(start 41.34231 -266.84605)
		(end 41.083992 -266.84605)
		(width 0.18288)
		(layer "In6.Cu")
		(net "M_C_CPU1_SA_CB<7>")
	)
	(segment
		(start 60.583318 -262.343646)
		(end 60.214002 -262.343646)
		(width 0.18288)
		(layer "In6.Cu")
		(net "M_C_CPU1_SA_CB<7>")
	)
	(segment
		(start 54.035706 -262.48868)
		(end 53.710586 -262.48868)
		(width 0.18288)
		(layer "In6.Cu")
		(net "M_C_CPU1_SA_CB<7>")
	)
	(segment
		(start 96.062292 -259.289042)
		(end 96.056196 -259.292598)
		(width 0.088646)
		(layer "In6.Cu")
		(net "M_C_CPU1_SA_CB<7>")
	)
	(segment
		(start 61.558932 -261.368032)
		(end 60.583318 -262.343646)
		(width 0.18288)
		(layer "In6.Cu")
		(net "M_C_CPU1_SA_CB<7>")
	)
	(segment
		(start 43.109134 -265.079226)
		(end 41.34231 -266.84605)
		(width 0.18288)
		(layer "In6.Cu")
		(net "M_C_CPU1_SA_CB<7>")
	)
	(segment
		(start 40.595042 -267.593318)
		(end 39.899844 -268.288516)
		(width 0.18288)
		(layer "In6.Cu")
		(net "M_C_CPU1_SA_CB<7>")
	)
	(segment
		(start 62.935612 -261.368032)
		(end 61.558932 -261.368032)
		(width 0.18288)
		(layer "In6.Cu")
		(net "M_C_CPU1_SA_CB<7>")
	)
	(segment
		(start 81.081372 -259.234178)
		(end 77.921358 -260.54304)
		(width 0.18288)
		(layer "In6.Cu")
		(net "M_C_CPU1_SA_CB<7>")
	)
	(segment
		(start 40.350948 -266.113006)
		(end 40.092376 -266.113006)
		(width 0.18288)
		(layer "In6.Cu")
		(net "M_C_CPU1_SA_CB<7>")
	)
	(segment
		(start 54.218586 -263.00811)
		(end 54.218586 -262.67156)
		(width 0.18288)
		(layer "In6.Cu")
		(net "M_C_CPU1_SA_CB<7>")
	)
	(segment
		(start 48.451262 -263.19099)
		(end 47.601378 -264.040874)
		(width 0.18288)
		(layer "In6.Cu")
		(net "M_C_CPU1_SA_CB<7>")
	)
	(segment
		(start 52.836826 -263.00811)
		(end 52.836826 -262.67156)
		(width 0.18288)
		(layer "In6.Cu")
		(net "M_C_CPU1_SA_CB<7>")
	)
	(segment
		(start 52.653946 -262.48868)
		(end 52.328826 -262.48868)
		(width 0.18288)
		(layer "In6.Cu")
		(net "M_C_CPU1_SA_CB<7>")
	)
	(segment
		(start 84.025994 -258.554474)
		(end 83.34629 -259.234178)
		(width 0.088646)
		(layer "In6.Cu")
		(net "M_C_CPU1_SA_CB<7>")
	)
	(segment
		(start 39.862252 -266.601702)
		(end 40.595042 -267.334492)
		(width 0.18288)
		(layer "In6.Cu")
		(net "M_C_CPU1_SA_CB<7>")
	)
	(segment
		(start 60.053982 -262.848852)
		(end 59.893962 -263.008872)
		(width 0.18288)
		(layer "In6.Cu")
		(net "M_C_CPU1_SA_CB<7>")
	)
	(segment
		(start 53.527706 -263.00811)
		(end 53.344826 -263.19099)
		(width 0.18288)
		(layer "In6.Cu")
		(net "M_C_CPU1_SA_CB<7>")
	)
	(segment
		(start 93.156278 -258.487418)
		(end 93.141546 -258.478782)
		(width 0.088646)
		(layer "In6.Cu")
		(net "M_C_CPU1_SA_CB<7>")
	)
	(segment
		(start 44.099226 -265.079226)
		(end 43.109134 -265.079226)
		(width 0.18288)
		(layer "In6.Cu")
		(net "M_C_CPU1_SA_CB<7>")
	)
	(segment
		(start 90.88755 -258.478782)
		(end 90.877136 -258.484878)
		(width 0.088646)
		(layer "In6.Cu")
		(net "M_C_CPU1_SA_CB<7>")
	)
	(segment
		(start 36.61537 -269.778226)
		(end 35.976814 -270.416782)
		(width 0.18288)
		(layer "In6.Cu")
		(net "M_C_CPU1_SA_CB<7>")
	)
	(segment
		(start 53.527706 -262.67156)
		(end 53.527706 -263.00811)
		(width 0.18288)
		(layer "In6.Cu")
		(net "M_C_CPU1_SA_CB<7>")
	)
	(segment
		(start 37.579554 -269.778226)
		(end 36.61537 -269.778226)
		(width 0.18288)
		(layer "In6.Cu")
		(net "M_C_CPU1_SA_CB<7>")
	)
	(segment
		(start 60.053982 -262.503666)
		(end 60.053982 -262.848852)
		(width 0.18288)
		(layer "In6.Cu")
		(net "M_C_CPU1_SA_CB<7>")
	)
	(segment
		(start 55.961534 -262.343646)
		(end 55.11419 -263.19099)
		(width 0.18288)
		(layer "In6.Cu")
		(net "M_C_CPU1_SA_CB<7>")
	)
	(segment
		(start 54.401466 -263.19099)
		(end 54.218586 -263.00811)
		(width 0.18288)
		(layer "In6.Cu")
		(net "M_C_CPU1_SA_CB<7>")
	)
	(segment
		(start 45.137578 -264.040874)
		(end 44.099226 -265.079226)
		(width 0.18288)
		(layer "In6.Cu")
		(net "M_C_CPU1_SA_CB<7>")
	)
	(segment
		(start 39.899844 -268.288516)
		(end 39.069264 -268.288516)
		(width 0.18288)
		(layer "In6.Cu")
		(net "M_C_CPU1_SA_CB<7>")
	)
	(segment
		(start 54.218586 -262.67156)
		(end 54.035706 -262.48868)
		(width 0.18288)
		(layer "In6.Cu")
		(net "M_C_CPU1_SA_CB<7>")
	)
	(arc
		(start 85.622892 -258.478782)
		(mid 85.435694 -258.428639)
		(end 85.248496 -258.478782)
		(width 0.088646)
		(layer "In6.Cu")
		(net "M_C_CPU1_SA_CB<7>")
	)
	(arc
		(start 95.020892 -258.478782)
		(mid 94.833694 -258.428639)
		(end 94.646496 -258.478782)
		(width 0.088646)
		(layer "In6.Cu")
		(net "M_C_CPU1_SA_CB<7>")
	)
	(arc
		(start 93.70695 -258.478782)
		(mid 93.432721 -258.554707)
		(end 93.156278 -258.487418)
		(width 0.088646)
		(layer "In6.Cu")
		(net "M_C_CPU1_SA_CB<7>")
	)
	(arc
		(start 96.335088 -258.868926)
		(mid 96.2478 -259.110882)
		(end 96.062292 -259.289042)
		(width 0.088646)
		(layer "In6.Cu")
		(net "M_C_CPU1_SA_CB<7>")
	)
	(arc
		(start 84.308696 -258.478782)
		(mid 84.17233 -258.53526)
		(end 84.025994 -258.554474)
		(width 0.088646)
		(layer "In6.Cu")
		(net "M_C_CPU1_SA_CB<7>")
	)
	(arc
		(start 95.208344 -258.80314)
		(mid 95.160665 -258.62024)
		(end 95.029782 -258.483862)
		(width 0.088646)
		(layer "In6.Cu")
		(net "M_C_CPU1_SA_CB<7>")
	)
	(arc
		(start 88.442292 -258.478782)
		(mid 88.255094 -258.428639)
		(end 88.067896 -258.478782)
		(width 0.088646)
		(layer "In6.Cu")
		(net "M_C_CPU1_SA_CB<7>")
	)
	(arc
		(start 85.248496 -258.478782)
		(mid 84.965794 -258.554524)
		(end 84.683092 -258.478782)
		(width 0.088646)
		(layer "In6.Cu")
		(net "M_C_CPU1_SA_CB<7>")
	)
	(arc
		(start 96.041464 -259.301234)
		(mid 95.764989 -259.368554)
		(end 95.490792 -259.292598)
		(width 0.088646)
		(layer "In6.Cu")
		(net "M_C_CPU1_SA_CB<7>")
	)
	(arc
		(start 94.646496 -258.478782)
		(mid 94.369937 -258.554491)
		(end 94.09176 -258.484878)
		(width 0.088646)
		(layer "In6.Cu")
		(net "M_C_CPU1_SA_CB<7>")
	)
	(arc
		(start 92.201746 -258.478782)
		(mid 92.014548 -258.428639)
		(end 91.82735 -258.478782)
		(width 0.088646)
		(layer "In6.Cu")
		(net "M_C_CPU1_SA_CB<7>")
	)
	(arc
		(start 94.081346 -258.478782)
		(mid 93.894148 -258.428639)
		(end 93.70695 -258.478782)
		(width 0.088646)
		(layer "In6.Cu")
		(net "M_C_CPU1_SA_CB<7>")
	)
	(arc
		(start 86.562692 -258.478782)
		(mid 86.375494 -258.428639)
		(end 86.188296 -258.478782)
		(width 0.088646)
		(layer "In6.Cu")
		(net "M_C_CPU1_SA_CB<7>")
	)
	(arc
		(start 89.007696 -258.478782)
		(mid 88.724994 -258.554524)
		(end 88.442292 -258.478782)
		(width 0.088646)
		(layer "In6.Cu")
		(net "M_C_CPU1_SA_CB<7>")
	)
	(arc
		(start 91.261946 -258.478782)
		(mid 91.074748 -258.428639)
		(end 90.88755 -258.478782)
		(width 0.088646)
		(layer "In6.Cu")
		(net "M_C_CPU1_SA_CB<7>")
	)
	(arc
		(start 92.76715 -258.478782)
		(mid 92.484448 -258.554524)
		(end 92.201746 -258.478782)
		(width 0.088646)
		(layer "In6.Cu")
		(net "M_C_CPU1_SA_CB<7>")
	)
	(arc
		(start 87.502492 -258.478782)
		(mid 87.315294 -258.428639)
		(end 87.128096 -258.478782)
		(width 0.088646)
		(layer "In6.Cu")
		(net "M_C_CPU1_SA_CB<7>")
	)
	(arc
		(start 93.141546 -258.478782)
		(mid 92.954348 -258.428639)
		(end 92.76715 -258.478782)
		(width 0.088646)
		(layer "In6.Cu")
		(net "M_C_CPU1_SA_CB<7>")
	)
	(arc
		(start 90.321892 -258.478782)
		(mid 90.134694 -258.428639)
		(end 89.947496 -258.478782)
		(width 0.088646)
		(layer "In6.Cu")
		(net "M_C_CPU1_SA_CB<7>")
	)
	(arc
		(start 91.82735 -258.478782)
		(mid 91.553121 -258.554707)
		(end 91.276678 -258.487418)
		(width 0.088646)
		(layer "In6.Cu")
		(net "M_C_CPU1_SA_CB<7>")
	)
	(arc
		(start 90.877136 -258.484878)
		(mid 90.598704 -258.554692)
		(end 90.321892 -258.478782)
		(width 0.088646)
		(layer "In6.Cu")
		(net "M_C_CPU1_SA_CB<7>")
	)
	(arc
		(start 86.188296 -258.478782)
		(mid 85.905594 -258.554524)
		(end 85.622892 -258.478782)
		(width 0.088646)
		(layer "In6.Cu")
		(net "M_C_CPU1_SA_CB<7>")
	)
	(arc
		(start 88.067896 -258.478782)
		(mid 87.785194 -258.554524)
		(end 87.502492 -258.478782)
		(width 0.088646)
		(layer "In6.Cu")
		(net "M_C_CPU1_SA_CB<7>")
	)
	(arc
		(start 87.128096 -258.478782)
		(mid 86.845394 -258.554524)
		(end 86.562692 -258.478782)
		(width 0.088646)
		(layer "In6.Cu")
		(net "M_C_CPU1_SA_CB<7>")
	)
	(arc
		(start 95.484696 -259.289042)
		(mid 95.282283 -259.082629)
		(end 95.208344 -258.80314)
		(width 0.088646)
		(layer "In6.Cu")
		(net "M_C_CPU1_SA_CB<7>")
	)
	(arc
		(start 89.382092 -258.478782)
		(mid 89.194894 -258.428639)
		(end 89.007696 -258.478782)
		(width 0.088646)
		(layer "In6.Cu")
		(net "M_C_CPU1_SA_CB<7>")
	)
	(arc
		(start 84.683092 -258.478782)
		(mid 84.495894 -258.428639)
		(end 84.308696 -258.478782)
		(width 0.088646)
		(layer "In6.Cu")
		(net "M_C_CPU1_SA_CB<7>")
	)
	(arc
		(start 89.947496 -258.478782)
		(mid 89.664794 -258.554524)
		(end 89.382092 -258.478782)
		(width 0.088646)
		(layer "In6.Cu")
		(net "M_C_CPU1_SA_CB<7>")
	)
	(segment
		(start 31.972758 -271.691862)
		(end 32.041084 -271.691862)
		(width 0.101854)
		(layer "F.Cu")
		(net "M_C_CPU1_SA_CB<6>")
	)
	(segment
		(start 97.183448 -259.616702)
		(end 97.183194 -259.616956)
		(width 0.20066)
		(layer "F.Cu")
		(net "M_C_CPU1_SA_CB<6>")
	)
	(segment
		(start 33.345374 -272.32864)
		(end 33.55721 -272.116804)
		(width 0.20066)
		(layer "F.Cu")
		(net "M_C_CPU1_SA_CB<6>")
	)
	(segment
		(start 27.328114 -272.116804)
		(end 28.475178 -272.116804)
		(width 0.20066)
		(layer "F.Cu")
		(net "M_C_CPU1_SA_CB<6>")
	)
	(segment
		(start 28.475178 -272.116804)
		(end 28.90012 -271.691862)
		(width 0.20066)
		(layer "F.Cu")
		(net "M_C_CPU1_SA_CB<6>")
	)
	(segment
		(start 32.916876 -272.32864)
		(end 33.345374 -272.32864)
		(width 0.20066)
		(layer "F.Cu")
		(net "M_C_CPU1_SA_CB<6>")
	)
	(segment
		(start 29.912818 -271.691862)
		(end 31.972758 -271.691862)
		(width 0.1016)
		(layer "F.Cu")
		(net "M_C_CPU1_SA_CB<6>")
	)
	(segment
		(start 32.74949 -272.161254)
		(end 32.916876 -272.32864)
		(width 0.20066)
		(layer "F.Cu")
		(net "M_C_CPU1_SA_CB<6>")
	)
	(segment
		(start 29.520388 -271.691862)
		(end 29.912818 -271.691862)
		(width 0.101854)
		(layer "F.Cu")
		(net "M_C_CPU1_SA_CB<6>")
	)
	(segment
		(start 97.183448 -259.081016)
		(end 97.183448 -259.616702)
		(width 0.20066)
		(layer "F.Cu")
		(net "M_C_CPU1_SA_CB<6>")
	)
	(segment
		(start 32.605726 -271.691862)
		(end 32.74949 -271.835626)
		(width 0.20066)
		(layer "F.Cu")
		(net "M_C_CPU1_SA_CB<6>")
	)
	(segment
		(start 35.976814 -272.116804)
		(end 34.871914 -272.116804)
		(width 0.20066)
		(layer "F.Cu")
		(net "M_C_CPU1_SA_CB<6>")
	)
	(segment
		(start 32.041084 -271.691862)
		(end 32.605726 -271.691862)
		(width 0.20066)
		(layer "F.Cu")
		(net "M_C_CPU1_SA_CB<6>")
	)
	(segment
		(start 32.74949 -271.835626)
		(end 32.74949 -272.161254)
		(width 0.20066)
		(layer "F.Cu")
		(net "M_C_CPU1_SA_CB<6>")
	)
	(segment
		(start 33.55721 -272.116804)
		(end 34.871914 -272.116804)
		(width 0.20066)
		(layer "F.Cu")
		(net "M_C_CPU1_SA_CB<6>")
	)
	(segment
		(start 28.90012 -271.691862)
		(end 29.520388 -271.691862)
		(width 0.20066)
		(layer "F.Cu")
		(net "M_C_CPU1_SA_CB<6>")
	)
	(segment
		(start 59.440826 -264.645648)
		(end 58.805826 -264.010648)
		(width 0.18288)
		(layer "In6.Cu")
		(net "M_C_CPU1_SA_CB<6>")
	)
	(segment
		(start 92.296996 -259.292598)
		(end 92.286582 -259.298694)
		(width 0.088646)
		(layer "In6.Cu")
		(net "M_C_CPU1_SA_CB<6>")
	)
	(segment
		(start 67.843146 -261.551674)
		(end 67.210178 -262.184642)
		(width 0.18288)
		(layer "In6.Cu")
		(net "M_C_CPU1_SA_CB<6>")
	)
	(segment
		(start 61.859922 -263.191752)
		(end 60.406026 -264.645648)
		(width 0.18288)
		(layer "In6.Cu")
		(net "M_C_CPU1_SA_CB<6>")
	)
	(segment
		(start 53.606954 -265.073892)
		(end 53.606954 -265.29411)
		(width 0.18288)
		(layer "In6.Cu")
		(net "M_C_CPU1_SA_CB<6>")
	)
	(segment
		(start 60.406026 -264.645648)
		(end 59.440826 -264.645648)
		(width 0.18288)
		(layer "In6.Cu")
		(net "M_C_CPU1_SA_CB<6>")
	)
	(segment
		(start 53.606954 -265.29411)
		(end 53.424074 -265.47699)
		(width 0.18288)
		(layer "In6.Cu")
		(net "M_C_CPU1_SA_CB<6>")
	)
	(segment
		(start 45.55363 -266.38631)
		(end 44.476416 -266.38631)
		(width 0.18288)
		(layer "In6.Cu")
		(net "M_C_CPU1_SA_CB<6>")
	)
	(segment
		(start 84.449412 -259.366512)
		(end 83.970368 -259.366512)
		(width 0.088646)
		(layer "In6.Cu")
		(net "M_C_CPU1_SA_CB<6>")
	)
	(segment
		(start 40.289226 -269.879826)
		(end 39.273226 -269.879826)
		(width 0.18288)
		(layer "In6.Cu")
		(net "M_C_CPU1_SA_CB<6>")
	)
	(segment
		(start 47.374556 -265.740896)
		(end 46.199044 -265.740896)
		(width 0.18288)
		(layer "In6.Cu")
		(net "M_C_CPU1_SA_CB<6>")
	)
	(segment
		(start 81.189322 -260.267958)
		(end 78.08976 -261.551674)
		(width 0.18288)
		(layer "In6.Cu")
		(net "M_C_CPU1_SA_CB<6>")
	)
	(segment
		(start 93.236796 -259.292598)
		(end 93.222064 -259.301234)
		(width 0.088646)
		(layer "In6.Cu")
		(net "M_C_CPU1_SA_CB<6>")
	)
	(segment
		(start 46.199044 -265.740896)
		(end 45.55363 -266.38631)
		(width 0.18288)
		(layer "In6.Cu")
		(net "M_C_CPU1_SA_CB<6>")
	)
	(segment
		(start 94.593156 -259.318252)
		(end 94.550992 -259.292598)
		(width 0.088646)
		(layer "In6.Cu")
		(net "M_C_CPU1_SA_CB<6>")
	)
	(segment
		(start 54.852062 -264.891012)
		(end 53.789834 -264.891012)
		(width 0.18288)
		(layer "In6.Cu")
		(net "M_C_CPU1_SA_CB<6>")
	)
	(segment
		(start 55.732426 -264.010648)
		(end 54.852062 -264.891012)
		(width 0.18288)
		(layer "In6.Cu")
		(net "M_C_CPU1_SA_CB<6>")
	)
	(segment
		(start 39.273226 -269.879826)
		(end 37.698426 -271.454626)
		(width 0.18288)
		(layer "In6.Cu")
		(net "M_C_CPU1_SA_CB<6>")
	)
	(segment
		(start 82.65795 -260.267958)
		(end 81.189322 -260.267958)
		(width 0.18288)
		(layer "In6.Cu")
		(net "M_C_CPU1_SA_CB<6>")
	)
	(segment
		(start 36.638992 -271.454626)
		(end 35.976814 -272.116804)
		(width 0.18288)
		(layer "In6.Cu")
		(net "M_C_CPU1_SA_CB<6>")
	)
	(segment
		(start 62.607698 -263.351772)
		(end 62.447678 -263.191752)
		(width 0.18288)
		(layer "In6.Cu")
		(net "M_C_CPU1_SA_CB<6>")
	)
	(segment
		(start 44.476416 -266.38631)
		(end 44.02074 -266.841986)
		(width 0.18288)
		(layer "In6.Cu")
		(net "M_C_CPU1_SA_CB<6>")
	)
	(segment
		(start 57.693814 -264.193528)
		(end 57.693814 -264.625328)
		(width 0.18288)
		(layer "In6.Cu")
		(net "M_C_CPU1_SA_CB<6>")
	)
	(segment
		(start 44.02074 -267.246354)
		(end 43.827446 -267.439648)
		(width 0.18288)
		(layer "In6.Cu")
		(net "M_C_CPU1_SA_CB<6>")
	)
	(segment
		(start 64.952626 -263.191752)
		(end 63.461138 -263.191752)
		(width 0.18288)
		(layer "In6.Cu")
		(net "M_C_CPU1_SA_CB<6>")
	)
	(segment
		(start 63.301118 -263.351772)
		(end 63.301118 -263.928352)
		(width 0.18288)
		(layer "In6.Cu")
		(net "M_C_CPU1_SA_CB<6>")
	)
	(segment
		(start 53.098954 -265.47699)
		(end 52.916074 -265.29411)
		(width 0.18288)
		(layer "In6.Cu")
		(net "M_C_CPU1_SA_CB<6>")
	)
	(segment
		(start 52.916074 -265.073892)
		(end 52.733194 -264.891012)
		(width 0.18288)
		(layer "In6.Cu")
		(net "M_C_CPU1_SA_CB<6>")
	)
	(segment
		(start 57.002934 -264.625328)
		(end 57.002934 -264.193528)
		(width 0.18288)
		(layer "In6.Cu")
		(net "M_C_CPU1_SA_CB<6>")
	)
	(segment
		(start 83.970368 -259.366512)
		(end 83.068922 -260.267958)
		(width 0.088646)
		(layer "In6.Cu")
		(net "M_C_CPU1_SA_CB<6>")
	)
	(segment
		(start 83.068922 -260.267958)
		(end 82.65795 -260.267958)
		(width 0.088646)
		(layer "In6.Cu")
		(net "M_C_CPU1_SA_CB<6>")
	)
	(segment
		(start 67.210178 -262.184642)
		(end 65.959736 -262.184642)
		(width 0.18288)
		(layer "In6.Cu")
		(net "M_C_CPU1_SA_CB<6>")
	)
	(segment
		(start 56.820054 -264.010648)
		(end 55.732426 -264.010648)
		(width 0.18288)
		(layer "In6.Cu")
		(net "M_C_CPU1_SA_CB<6>")
	)
	(segment
		(start 41.889426 -269.092426)
		(end 41.076626 -269.092426)
		(width 0.18288)
		(layer "In6.Cu")
		(net "M_C_CPU1_SA_CB<6>")
	)
	(segment
		(start 91.35745 -259.292598)
		(end 91.347036 -259.298694)
		(width 0.088646)
		(layer "In6.Cu")
		(net "M_C_CPU1_SA_CB<6>")
	)
	(segment
		(start 53.424074 -265.47699)
		(end 53.098954 -265.47699)
		(width 0.18288)
		(layer "In6.Cu")
		(net "M_C_CPU1_SA_CB<6>")
	)
	(segment
		(start 52.916074 -265.29411)
		(end 52.916074 -265.073892)
		(width 0.18288)
		(layer "In6.Cu")
		(net "M_C_CPU1_SA_CB<6>")
	)
	(segment
		(start 57.510934 -264.808208)
		(end 57.185814 -264.808208)
		(width 0.18288)
		(layer "In6.Cu")
		(net "M_C_CPU1_SA_CB<6>")
	)
	(segment
		(start 63.461138 -263.191752)
		(end 63.301118 -263.351772)
		(width 0.18288)
		(layer "In6.Cu")
		(net "M_C_CPU1_SA_CB<6>")
	)
	(segment
		(start 62.607698 -263.928352)
		(end 62.607698 -263.351772)
		(width 0.18288)
		(layer "In6.Cu")
		(net "M_C_CPU1_SA_CB<6>")
	)
	(segment
		(start 94.668848 -259.375148)
		(end 94.593156 -259.318252)
		(width 0.088646)
		(layer "In6.Cu")
		(net "M_C_CPU1_SA_CB<6>")
	)
	(segment
		(start 44.02074 -266.841986)
		(end 44.02074 -267.246354)
		(width 0.18288)
		(layer "In6.Cu")
		(net "M_C_CPU1_SA_CB<6>")
	)
	(segment
		(start 43.827446 -267.439648)
		(end 42.966894 -267.439648)
		(width 0.18288)
		(layer "In6.Cu")
		(net "M_C_CPU1_SA_CB<6>")
	)
	(segment
		(start 94.7928 -259.50799)
		(end 94.668848 -259.375148)
		(width 0.088646)
		(layer "In6.Cu")
		(net "M_C_CPU1_SA_CB<6>")
	)
	(segment
		(start 41.076626 -269.092426)
		(end 40.289226 -269.879826)
		(width 0.18288)
		(layer "In6.Cu")
		(net "M_C_CPU1_SA_CB<6>")
	)
	(segment
		(start 94.176596 -259.292598)
		(end 94.161864 -259.301234)
		(width 0.088646)
		(layer "In6.Cu")
		(net "M_C_CPU1_SA_CB<6>")
	)
	(segment
		(start 63.141098 -264.088372)
		(end 62.767718 -264.088372)
		(width 0.18288)
		(layer "In6.Cu")
		(net "M_C_CPU1_SA_CB<6>")
	)
	(segment
		(start 42.803826 -268.178026)
		(end 41.889426 -269.092426)
		(width 0.18288)
		(layer "In6.Cu")
		(net "M_C_CPU1_SA_CB<6>")
	)
	(segment
		(start 57.185814 -264.808208)
		(end 57.002934 -264.625328)
		(width 0.18288)
		(layer "In6.Cu")
		(net "M_C_CPU1_SA_CB<6>")
	)
	(segment
		(start 57.002934 -264.193528)
		(end 56.820054 -264.010648)
		(width 0.18288)
		(layer "In6.Cu")
		(net "M_C_CPU1_SA_CB<6>")
	)
	(segment
		(start 62.447678 -263.191752)
		(end 61.859922 -263.191752)
		(width 0.18288)
		(layer "In6.Cu")
		(net "M_C_CPU1_SA_CB<6>")
	)
	(segment
		(start 52.733194 -264.891012)
		(end 48.22444 -264.891012)
		(width 0.18288)
		(layer "In6.Cu")
		(net "M_C_CPU1_SA_CB<6>")
	)
	(segment
		(start 37.698426 -271.454626)
		(end 36.638992 -271.454626)
		(width 0.18288)
		(layer "In6.Cu")
		(net "M_C_CPU1_SA_CB<6>")
	)
	(segment
		(start 58.805826 -264.010648)
		(end 57.876694 -264.010648)
		(width 0.18288)
		(layer "In6.Cu")
		(net "M_C_CPU1_SA_CB<6>")
	)
	(segment
		(start 57.693814 -264.625328)
		(end 57.510934 -264.808208)
		(width 0.18288)
		(layer "In6.Cu")
		(net "M_C_CPU1_SA_CB<6>")
	)
	(segment
		(start 63.301118 -263.928352)
		(end 63.141098 -264.088372)
		(width 0.18288)
		(layer "In6.Cu")
		(net "M_C_CPU1_SA_CB<6>")
	)
	(segment
		(start 42.803826 -267.602716)
		(end 42.803826 -268.178026)
		(width 0.18288)
		(layer "In6.Cu")
		(net "M_C_CPU1_SA_CB<6>")
	)
	(segment
		(start 65.959736 -262.184642)
		(end 64.952626 -263.191752)
		(width 0.18288)
		(layer "In6.Cu")
		(net "M_C_CPU1_SA_CB<6>")
	)
	(segment
		(start 94.846648 -259.605272)
		(end 94.7928 -259.50799)
		(width 0.088646)
		(layer "In6.Cu")
		(net "M_C_CPU1_SA_CB<6>")
	)
	(segment
		(start 48.22444 -264.891012)
		(end 47.374556 -265.740896)
		(width 0.18288)
		(layer "In6.Cu")
		(net "M_C_CPU1_SA_CB<6>")
	)
	(segment
		(start 53.789834 -264.891012)
		(end 53.606954 -265.073892)
		(width 0.18288)
		(layer "In6.Cu")
		(net "M_C_CPU1_SA_CB<6>")
	)
	(segment
		(start 62.767718 -264.088372)
		(end 62.607698 -263.928352)
		(width 0.18288)
		(layer "In6.Cu")
		(net "M_C_CPU1_SA_CB<6>")
	)
	(segment
		(start 57.876694 -264.010648)
		(end 57.693814 -264.193528)
		(width 0.18288)
		(layer "In6.Cu")
		(net "M_C_CPU1_SA_CB<6>")
	)
	(segment
		(start 42.966894 -267.439648)
		(end 42.803826 -267.602716)
		(width 0.18288)
		(layer "In6.Cu")
		(net "M_C_CPU1_SA_CB<6>")
	)
	(segment
		(start 78.08976 -261.551674)
		(end 67.843146 -261.551674)
		(width 0.18288)
		(layer "In6.Cu")
		(net "M_C_CPU1_SA_CB<6>")
	)
	(arc
		(start 95.490792 -259.941314)
		(mid 95.303594 -259.991457)
		(end 95.116396 -259.941314)
		(width 0.088646)
		(layer "In6.Cu")
		(net "M_C_CPU1_SA_CB<6>")
	)
	(arc
		(start 94.903544 -259.688076)
		(mid 94.875663 -259.646284)
		(end 94.846648 -259.605272)
		(width 0.088646)
		(layer "In6.Cu")
		(net "M_C_CPU1_SA_CB<6>")
	)
	(arc
		(start 94.550992 -259.292598)
		(mid 94.363794 -259.242455)
		(end 94.176596 -259.292598)
		(width 0.088646)
		(layer "In6.Cu")
		(net "M_C_CPU1_SA_CB<6>")
	)
	(arc
		(start 92.286582 -259.298694)
		(mid 92.008404 -259.368417)
		(end 91.731846 -259.292598)
		(width 0.088646)
		(layer "In6.Cu")
		(net "M_C_CPU1_SA_CB<6>")
	)
	(arc
		(start 95.974154 -259.90169)
		(mid 95.728016 -259.867064)
		(end 95.490792 -259.941314)
		(width 0.088646)
		(layer "In6.Cu")
		(net "M_C_CPU1_SA_CB<6>")
	)
	(arc
		(start 93.611192 -259.292598)
		(mid 93.423994 -259.242455)
		(end 93.236796 -259.292598)
		(width 0.088646)
		(layer "In6.Cu")
		(net "M_C_CPU1_SA_CB<6>")
	)
	(arc
		(start 96.396302 -259.973826)
		(mid 96.360281 -259.976425)
		(end 96.324674 -259.982462)
		(width 0.088646)
		(layer "In6.Cu")
		(net "M_C_CPU1_SA_CB<6>")
	)
	(arc
		(start 86.092792 -259.292598)
		(mid 85.905594 -259.242455)
		(end 85.718396 -259.292598)
		(width 0.088646)
		(layer "In6.Cu")
		(net "M_C_CPU1_SA_CB<6>")
	)
	(arc
		(start 88.912192 -259.292598)
		(mid 88.724994 -259.242455)
		(end 88.537796 -259.292598)
		(width 0.088646)
		(layer "In6.Cu")
		(net "M_C_CPU1_SA_CB<6>")
	)
	(arc
		(start 86.658196 -259.292598)
		(mid 86.375494 -259.368374)
		(end 86.092792 -259.292598)
		(width 0.088646)
		(layer "In6.Cu")
		(net "M_C_CPU1_SA_CB<6>")
	)
	(arc
		(start 87.597996 -259.292598)
		(mid 87.315294 -259.368374)
		(end 87.032592 -259.292598)
		(width 0.088646)
		(layer "In6.Cu")
		(net "M_C_CPU1_SA_CB<6>")
	)
	(arc
		(start 96.324674 -259.982462)
		(mid 96.185292 -259.987046)
		(end 96.05391 -259.940298)
		(width 0.088646)
		(layer "In6.Cu")
		(net "M_C_CPU1_SA_CB<6>")
	)
	(arc
		(start 87.032592 -259.292598)
		(mid 86.845394 -259.242455)
		(end 86.658196 -259.292598)
		(width 0.088646)
		(layer "In6.Cu")
		(net "M_C_CPU1_SA_CB<6>")
	)
	(arc
		(start 88.537796 -259.292598)
		(mid 88.255094 -259.368374)
		(end 87.972392 -259.292598)
		(width 0.088646)
		(layer "In6.Cu")
		(net "M_C_CPU1_SA_CB<6>")
	)
	(arc
		(start 94.161864 -259.301234)
		(mid 93.885389 -259.368554)
		(end 93.611192 -259.292598)
		(width 0.088646)
		(layer "In6.Cu")
		(net "M_C_CPU1_SA_CB<6>")
	)
	(arc
		(start 85.152992 -259.292598)
		(mid 84.965794 -259.242455)
		(end 84.778596 -259.292598)
		(width 0.088646)
		(layer "In6.Cu")
		(net "M_C_CPU1_SA_CB<6>")
	)
	(arc
		(start 91.731846 -259.292598)
		(mid 91.544648 -259.242455)
		(end 91.35745 -259.292598)
		(width 0.088646)
		(layer "In6.Cu")
		(net "M_C_CPU1_SA_CB<6>")
	)
	(arc
		(start 89.851992 -259.292598)
		(mid 89.664794 -259.242455)
		(end 89.477596 -259.292598)
		(width 0.088646)
		(layer "In6.Cu")
		(net "M_C_CPU1_SA_CB<6>")
	)
	(arc
		(start 92.671392 -259.292598)
		(mid 92.484194 -259.242455)
		(end 92.296996 -259.292598)
		(width 0.088646)
		(layer "In6.Cu")
		(net "M_C_CPU1_SA_CB<6>")
	)
	(arc
		(start 93.222064 -259.301234)
		(mid 92.945589 -259.368554)
		(end 92.671392 -259.292598)
		(width 0.088646)
		(layer "In6.Cu")
		(net "M_C_CPU1_SA_CB<6>")
	)
	(arc
		(start 95.116396 -259.941314)
		(mid 94.987665 -259.833439)
		(end 94.903544 -259.688076)
		(width 0.088646)
		(layer "In6.Cu")
		(net "M_C_CPU1_SA_CB<6>")
	)
	(arc
		(start 90.417396 -259.292598)
		(mid 90.134694 -259.368374)
		(end 89.851992 -259.292598)
		(width 0.088646)
		(layer "In6.Cu")
		(net "M_C_CPU1_SA_CB<6>")
	)
	(arc
		(start 91.347036 -259.298694)
		(mid 91.068604 -259.36854)
		(end 90.791792 -259.292598)
		(width 0.088646)
		(layer "In6.Cu")
		(net "M_C_CPU1_SA_CB<6>")
	)
	(arc
		(start 97.183194 -259.616956)
		(mid 96.825913 -259.875138)
		(end 96.396302 -259.973826)
		(width 0.088646)
		(layer "In6.Cu")
		(net "M_C_CPU1_SA_CB<6>")
	)
	(arc
		(start 96.05391 -259.940298)
		(mid 96.014845 -259.919315)
		(end 95.974154 -259.90169)
		(width 0.088646)
		(layer "In6.Cu")
		(net "M_C_CPU1_SA_CB<6>")
	)
	(arc
		(start 85.718396 -259.292598)
		(mid 85.435694 -259.368374)
		(end 85.152992 -259.292598)
		(width 0.088646)
		(layer "In6.Cu")
		(net "M_C_CPU1_SA_CB<6>")
	)
	(arc
		(start 90.791792 -259.292598)
		(mid 90.604594 -259.242455)
		(end 90.417396 -259.292598)
		(width 0.088646)
		(layer "In6.Cu")
		(net "M_C_CPU1_SA_CB<6>")
	)
	(arc
		(start 89.477596 -259.292598)
		(mid 89.194894 -259.368374)
		(end 88.912192 -259.292598)
		(width 0.088646)
		(layer "In6.Cu")
		(net "M_C_CPU1_SA_CB<6>")
	)
	(arc
		(start 84.778596 -259.292598)
		(mid 84.619645 -259.354661)
		(end 84.449412 -259.366512)
		(width 0.088646)
		(layer "In6.Cu")
		(net "M_C_CPU1_SA_CB<6>")
	)
	(arc
		(start 87.972392 -259.292598)
		(mid 87.785194 -259.242455)
		(end 87.597996 -259.292598)
		(width 0.088646)
		(layer "In6.Cu")
		(net "M_C_CPU1_SA_CB<6>")
	)
	(segment
		(start 23.228046 -271.266666)
		(end 24.562308 -271.266666)
		(width 0.20066)
		(layer "F.Cu")
		(net "M_C_CPU1_SA_CB<5>")
	)
	(segment
		(start 95.773494 -258.802886)
		(end 95.773748 -258.80314)
		(width 0.20066)
		(layer "F.Cu")
		(net "M_C_CPU1_SA_CB<5>")
	)
	(segment
		(start 29.13253 -271.266666)
		(end 30.771846 -271.266666)
		(width 0.20066)
		(layer "F.Cu")
		(net "M_C_CPU1_SA_CB<5>")
	)
	(segment
		(start 95.773494 -258.2672)
		(end 95.773494 -258.802886)
		(width 0.20066)
		(layer "F.Cu")
		(net "M_C_CPU1_SA_CB<5>")
	)
	(segment
		(start 28.707588 -270.841724)
		(end 29.13253 -271.266666)
		(width 0.20066)
		(layer "F.Cu")
		(net "M_C_CPU1_SA_CB<5>")
	)
	(segment
		(start 25.595072 -270.841724)
		(end 26.082498 -270.841724)
		(width 0.20066)
		(layer "F.Cu")
		(net "M_C_CPU1_SA_CB<5>")
	)
	(segment
		(start 25.27808 -271.477994)
		(end 25.432512 -271.323562)
		(width 0.20066)
		(layer "F.Cu")
		(net "M_C_CPU1_SA_CB<5>")
	)
	(segment
		(start 26.082498 -270.841724)
		(end 26.2128 -270.841724)
		(width 0.101854)
		(layer "F.Cu")
		(net "M_C_CPU1_SA_CB<5>")
	)
	(segment
		(start 25.432512 -271.004284)
		(end 25.595072 -270.841724)
		(width 0.20066)
		(layer "F.Cu")
		(net "M_C_CPU1_SA_CB<5>")
	)
	(segment
		(start 24.773636 -271.477994)
		(end 25.27808 -271.477994)
		(width 0.20066)
		(layer "F.Cu")
		(net "M_C_CPU1_SA_CB<5>")
	)
	(segment
		(start 26.2128 -270.841724)
		(end 28.198318 -270.841724)
		(width 0.1016)
		(layer "F.Cu")
		(net "M_C_CPU1_SA_CB<5>")
	)
	(segment
		(start 28.603194 -270.841724)
		(end 28.707588 -270.841724)
		(width 0.20066)
		(layer "F.Cu")
		(net "M_C_CPU1_SA_CB<5>")
	)
	(segment
		(start 25.432512 -271.323562)
		(end 25.432512 -271.004284)
		(width 0.20066)
		(layer "F.Cu")
		(net "M_C_CPU1_SA_CB<5>")
	)
	(segment
		(start 28.198318 -270.841724)
		(end 28.603194 -270.841724)
		(width 0.101854)
		(layer "F.Cu")
		(net "M_C_CPU1_SA_CB<5>")
	)
	(segment
		(start 31.876746 -271.266666)
		(end 30.771846 -271.266666)
		(width 0.20066)
		(layer "F.Cu")
		(net "M_C_CPU1_SA_CB<5>")
	)
	(segment
		(start 24.562308 -271.266666)
		(end 24.773636 -271.477994)
		(width 0.20066)
		(layer "F.Cu")
		(net "M_C_CPU1_SA_CB<5>")
	)
	(segment
		(start 37.987478 -267.505942)
		(end 37.987478 -268.586712)
		(width 0.18288)
		(layer "In6.Cu")
		(net "M_C_CPU1_SA_CB<5>")
	)
	(segment
		(start 83.907122 -258.364228)
		(end 83.537552 -258.733798)
		(width 0.088646)
		(layer "In6.Cu")
		(net "M_C_CPU1_SA_CB<5>")
	)
	(segment
		(start 51.681126 -261.739126)
		(end 51.681126 -262.066532)
		(width 0.18288)
		(layer "In6.Cu")
		(net "M_C_CPU1_SA_CB<5>")
	)
	(segment
		(start 57.239154 -261.103872)
		(end 57.239154 -261.329932)
		(width 0.18288)
		(layer "In6.Cu")
		(net "M_C_CPU1_SA_CB<5>")
	)
	(segment
		(start 58.092594 -261.489952)
		(end 57.932574 -261.329932)
		(width 0.18288)
		(layer "In6.Cu")
		(net "M_C_CPU1_SA_CB<5>")
	)
	(segment
		(start 44.109132 -263.190736)
		(end 42.311828 -264.98804)
		(width 0.18288)
		(layer "In6.Cu")
		(net "M_C_CPU1_SA_CB<5>")
	)
	(segment
		(start 57.772554 -260.943852)
		(end 57.399174 -260.943852)
		(width 0.18288)
		(layer "In6.Cu")
		(net "M_C_CPU1_SA_CB<5>")
	)
	(segment
		(start 95.399098 -258.80314)
		(end 95.399098 -258.79552)
		(width 0.088646)
		(layer "In6.Cu")
		(net "M_C_CPU1_SA_CB<5>")
	)
	(segment
		(start 59.2836 -261.489952)
		(end 58.092594 -261.489952)
		(width 0.18288)
		(layer "In6.Cu")
		(net "M_C_CPU1_SA_CB<5>")
	)
	(segment
		(start 62.473586 -260.832346)
		(end 59.941206 -260.832346)
		(width 0.18288)
		(layer "In6.Cu")
		(net "M_C_CPU1_SA_CB<5>")
	)
	(segment
		(start 63.267082 -260.03885)
		(end 62.473586 -260.832346)
		(width 0.18288)
		(layer "In6.Cu")
		(net "M_C_CPU1_SA_CB<5>")
	)
	(segment
		(start 91.357196 -258.313428)
		(end 91.346782 -258.307332)
		(width 0.088646)
		(layer "In6.Cu")
		(net "M_C_CPU1_SA_CB<5>")
	)
	(segment
		(start 51.406806 -262.340852)
		(end 48.158146 -262.340852)
		(width 0.18288)
		(layer "In6.Cu")
		(net "M_C_CPU1_SA_CB<5>")
	)
	(segment
		(start 92.29725 -258.313428)
		(end 92.286836 -258.307332)
		(width 0.088646)
		(layer "In6.Cu")
		(net "M_C_CPU1_SA_CB<5>")
	)
	(segment
		(start 40.50538 -264.98804)
		(end 37.987478 -267.505942)
		(width 0.18288)
		(layer "In6.Cu")
		(net "M_C_CPU1_SA_CB<5>")
	)
	(segment
		(start 93.236796 -258.313428)
		(end 93.226382 -258.307332)
		(width 0.088646)
		(layer "In6.Cu")
		(net "M_C_CPU1_SA_CB<5>")
	)
	(segment
		(start 96.086422 -258.80314)
		(end 96.143826 -258.860544)
		(width 0.088646)
		(layer "In6.Cu")
		(net "M_C_CPU1_SA_CB<5>")
	)
	(segment
		(start 80.988154 -258.733798)
		(end 77.83703 -260.03885)
		(width 0.18288)
		(layer "In6.Cu")
		(net "M_C_CPU1_SA_CB<5>")
	)
	(segment
		(start 42.311828 -264.98804)
		(end 40.50538 -264.98804)
		(width 0.18288)
		(layer "In6.Cu")
		(net "M_C_CPU1_SA_CB<5>")
	)
	(segment
		(start 51.9303 -261.489952)
		(end 51.681126 -261.739126)
		(width 0.18288)
		(layer "In6.Cu")
		(net "M_C_CPU1_SA_CB<5>")
	)
	(segment
		(start 57.239154 -261.329932)
		(end 57.079134 -261.489952)
		(width 0.18288)
		(layer "In6.Cu")
		(net "M_C_CPU1_SA_CB<5>")
	)
	(segment
		(start 94.176596 -258.313428)
		(end 94.161864 -258.304792)
		(width 0.088646)
		(layer "In6.Cu")
		(net "M_C_CPU1_SA_CB<5>")
	)
	(segment
		(start 34.942526 -269.142464)
		(end 32.818324 -271.266666)
		(width 0.18288)
		(layer "In6.Cu")
		(net "M_C_CPU1_SA_CB<5>")
	)
	(segment
		(start 57.932574 -261.329932)
		(end 57.932574 -261.103872)
		(width 0.18288)
		(layer "In6.Cu")
		(net "M_C_CPU1_SA_CB<5>")
	)
	(segment
		(start 57.079134 -261.489952)
		(end 51.9303 -261.489952)
		(width 0.18288)
		(layer "In6.Cu")
		(net "M_C_CPU1_SA_CB<5>")
	)
	(segment
		(start 57.932574 -261.103872)
		(end 57.772554 -260.943852)
		(width 0.18288)
		(layer "In6.Cu")
		(net "M_C_CPU1_SA_CB<5>")
	)
	(segment
		(start 83.088734 -258.733798)
		(end 80.988154 -258.733798)
		(width 0.18288)
		(layer "In6.Cu")
		(net "M_C_CPU1_SA_CB<5>")
	)
	(segment
		(start 37.987478 -268.586712)
		(end 37.431726 -269.142464)
		(width 0.18288)
		(layer "In6.Cu")
		(net "M_C_CPU1_SA_CB<5>")
	)
	(segment
		(start 77.83703 -260.03885)
		(end 63.267082 -260.03885)
		(width 0.18288)
		(layer "In6.Cu")
		(net "M_C_CPU1_SA_CB<5>")
	)
	(segment
		(start 51.681126 -262.066532)
		(end 51.406806 -262.340852)
		(width 0.18288)
		(layer "In6.Cu")
		(net "M_C_CPU1_SA_CB<5>")
	)
	(segment
		(start 48.158146 -262.340852)
		(end 47.308262 -263.190736)
		(width 0.18288)
		(layer "In6.Cu")
		(net "M_C_CPU1_SA_CB<5>")
	)
	(segment
		(start 57.399174 -260.943852)
		(end 57.239154 -261.103872)
		(width 0.18288)
		(layer "In6.Cu")
		(net "M_C_CPU1_SA_CB<5>")
	)
	(segment
		(start 95.969836 -259.122418)
		(end 95.960946 -259.127498)
		(width 0.088646)
		(layer "In6.Cu")
		(net "M_C_CPU1_SA_CB<5>")
	)
	(segment
		(start 83.537552 -258.733798)
		(end 83.088734 -258.733798)
		(width 0.088646)
		(layer "In6.Cu")
		(net "M_C_CPU1_SA_CB<5>")
	)
	(segment
		(start 84.025994 -258.364228)
		(end 83.907122 -258.364228)
		(width 0.088646)
		(layer "In6.Cu")
		(net "M_C_CPU1_SA_CB<5>")
	)
	(segment
		(start 95.773748 -258.80314)
		(end 96.086422 -258.80314)
		(width 0.088646)
		(layer "In6.Cu")
		(net "M_C_CPU1_SA_CB<5>")
	)
	(segment
		(start 47.308262 -263.190736)
		(end 44.109132 -263.190736)
		(width 0.18288)
		(layer "In6.Cu")
		(net "M_C_CPU1_SA_CB<5>")
	)
	(segment
		(start 95.58655 -259.127498)
		(end 95.57766 -259.122418)
		(width 0.088646)
		(layer "In6.Cu")
		(net "M_C_CPU1_SA_CB<5>")
	)
	(segment
		(start 59.941206 -260.832346)
		(end 59.2836 -261.489952)
		(width 0.18288)
		(layer "In6.Cu")
		(net "M_C_CPU1_SA_CB<5>")
	)
	(segment
		(start 89.862406 -258.307332)
		(end 89.851992 -258.313428)
		(width 0.088646)
		(layer "In6.Cu")
		(net "M_C_CPU1_SA_CB<5>")
	)
	(segment
		(start 32.818324 -271.266666)
		(end 31.876746 -271.266666)
		(width 0.18288)
		(layer "In6.Cu")
		(net "M_C_CPU1_SA_CB<5>")
	)
	(segment
		(start 37.431726 -269.142464)
		(end 34.942526 -269.142464)
		(width 0.18288)
		(layer "In6.Cu")
		(net "M_C_CPU1_SA_CB<5>")
	)
	(arc
		(start 89.851992 -258.313428)
		(mid 89.664794 -258.363571)
		(end 89.477596 -258.313428)
		(width 0.088646)
		(layer "In6.Cu")
		(net "M_C_CPU1_SA_CB<5>")
	)
	(arc
		(start 92.286836 -258.307332)
		(mid 92.008404 -258.237518)
		(end 91.731592 -258.313428)
		(width 0.088646)
		(layer "In6.Cu")
		(net "M_C_CPU1_SA_CB<5>")
	)
	(arc
		(start 91.346782 -258.307332)
		(mid 91.068604 -258.23764)
		(end 90.792046 -258.313428)
		(width 0.088646)
		(layer "In6.Cu")
		(net "M_C_CPU1_SA_CB<5>")
	)
	(arc
		(start 85.718396 -258.313428)
		(mid 85.435694 -258.237686)
		(end 85.152992 -258.313428)
		(width 0.088646)
		(layer "In6.Cu")
		(net "M_C_CPU1_SA_CB<5>")
	)
	(arc
		(start 87.032592 -258.313428)
		(mid 86.845394 -258.363571)
		(end 86.658196 -258.313428)
		(width 0.088646)
		(layer "In6.Cu")
		(net "M_C_CPU1_SA_CB<5>")
	)
	(arc
		(start 86.092792 -258.313428)
		(mid 85.905594 -258.363571)
		(end 85.718396 -258.313428)
		(width 0.088646)
		(layer "In6.Cu")
		(net "M_C_CPU1_SA_CB<5>")
	)
	(arc
		(start 90.41765 -258.313428)
		(mid 90.140837 -258.237592)
		(end 89.862406 -258.307332)
		(width 0.088646)
		(layer "In6.Cu")
		(net "M_C_CPU1_SA_CB<5>")
	)
	(arc
		(start 87.597996 -258.313428)
		(mid 87.315294 -258.237686)
		(end 87.032592 -258.313428)
		(width 0.088646)
		(layer "In6.Cu")
		(net "M_C_CPU1_SA_CB<5>")
	)
	(arc
		(start 90.792046 -258.313428)
		(mid 90.604848 -258.363571)
		(end 90.41765 -258.313428)
		(width 0.088646)
		(layer "In6.Cu")
		(net "M_C_CPU1_SA_CB<5>")
	)
	(arc
		(start 85.152992 -258.313428)
		(mid 84.965794 -258.363571)
		(end 84.778596 -258.313428)
		(width 0.088646)
		(layer "In6.Cu")
		(net "M_C_CPU1_SA_CB<5>")
	)
	(arc
		(start 92.671646 -258.313428)
		(mid 92.484448 -258.363571)
		(end 92.29725 -258.313428)
		(width 0.088646)
		(layer "In6.Cu")
		(net "M_C_CPU1_SA_CB<5>")
	)
	(arc
		(start 95.116396 -258.313428)
		(mid 94.833694 -258.237686)
		(end 94.550992 -258.313428)
		(width 0.088646)
		(layer "In6.Cu")
		(net "M_C_CPU1_SA_CB<5>")
	)
	(arc
		(start 94.550992 -258.313428)
		(mid 94.363794 -258.363571)
		(end 94.176596 -258.313428)
		(width 0.088646)
		(layer "In6.Cu")
		(net "M_C_CPU1_SA_CB<5>")
	)
	(arc
		(start 95.57766 -259.122418)
		(mid 95.446746 -258.986058)
		(end 95.399098 -258.80314)
		(width 0.088646)
		(layer "In6.Cu")
		(net "M_C_CPU1_SA_CB<5>")
	)
	(arc
		(start 88.537796 -258.313428)
		(mid 88.255094 -258.237686)
		(end 87.972392 -258.313428)
		(width 0.088646)
		(layer "In6.Cu")
		(net "M_C_CPU1_SA_CB<5>")
	)
	(arc
		(start 84.213192 -258.313428)
		(mid 84.122936 -258.35115)
		(end 84.025994 -258.364228)
		(width 0.088646)
		(layer "In6.Cu")
		(net "M_C_CPU1_SA_CB<5>")
	)
	(arc
		(start 95.399098 -258.79552)
		(mid 95.321469 -258.517107)
		(end 95.116396 -258.313428)
		(width 0.088646)
		(layer "In6.Cu")
		(net "M_C_CPU1_SA_CB<5>")
	)
	(arc
		(start 86.658196 -258.313428)
		(mid 86.375494 -258.237686)
		(end 86.092792 -258.313428)
		(width 0.088646)
		(layer "In6.Cu")
		(net "M_C_CPU1_SA_CB<5>")
	)
	(arc
		(start 84.778596 -258.313428)
		(mid 84.495894 -258.237686)
		(end 84.213192 -258.313428)
		(width 0.088646)
		(layer "In6.Cu")
		(net "M_C_CPU1_SA_CB<5>")
	)
	(arc
		(start 95.960946 -259.127498)
		(mid 95.773748 -259.177641)
		(end 95.58655 -259.127498)
		(width 0.088646)
		(layer "In6.Cu")
		(net "M_C_CPU1_SA_CB<5>")
	)
	(arc
		(start 88.912192 -258.313428)
		(mid 88.724994 -258.363571)
		(end 88.537796 -258.313428)
		(width 0.088646)
		(layer "In6.Cu")
		(net "M_C_CPU1_SA_CB<5>")
	)
	(arc
		(start 89.477596 -258.313428)
		(mid 89.194894 -258.237686)
		(end 88.912192 -258.313428)
		(width 0.088646)
		(layer "In6.Cu")
		(net "M_C_CPU1_SA_CB<5>")
	)
	(arc
		(start 87.972392 -258.313428)
		(mid 87.785194 -258.363571)
		(end 87.597996 -258.313428)
		(width 0.088646)
		(layer "In6.Cu")
		(net "M_C_CPU1_SA_CB<5>")
	)
	(arc
		(start 94.161864 -258.304792)
		(mid 93.885423 -258.237626)
		(end 93.611192 -258.313428)
		(width 0.088646)
		(layer "In6.Cu")
		(net "M_C_CPU1_SA_CB<5>")
	)
	(arc
		(start 93.226382 -258.307332)
		(mid 92.948204 -258.23764)
		(end 92.671646 -258.313428)
		(width 0.088646)
		(layer "In6.Cu")
		(net "M_C_CPU1_SA_CB<5>")
	)
	(arc
		(start 96.143826 -258.860544)
		(mid 96.08567 -259.010657)
		(end 95.969836 -259.122418)
		(width 0.088646)
		(layer "In6.Cu")
		(net "M_C_CPU1_SA_CB<5>")
	)
	(arc
		(start 91.731592 -258.313428)
		(mid 91.544394 -258.363571)
		(end 91.357196 -258.313428)
		(width 0.088646)
		(layer "In6.Cu")
		(net "M_C_CPU1_SA_CB<5>")
	)
	(arc
		(start 93.611192 -258.313428)
		(mid 93.423994 -258.363571)
		(end 93.236796 -258.313428)
		(width 0.088646)
		(layer "In6.Cu")
		(net "M_C_CPU1_SA_CB<5>")
	)
	(segment
		(start 26.086308 -272.541746)
		(end 26.459942 -272.541746)
		(width 0.101854)
		(layer "F.Cu")
		(net "M_C_CPU1_SA_CB<4>")
	)
	(segment
		(start 25.432512 -272.743168)
		(end 25.633934 -272.541746)
		(width 0.20066)
		(layer "F.Cu")
		(net "M_C_CPU1_SA_CB<4>")
	)
	(segment
		(start 28.598876 -272.541746)
		(end 28.977844 -272.541746)
		(width 0.20066)
		(layer "F.Cu")
		(net "M_C_CPU1_SA_CB<4>")
	)
	(segment
		(start 28.529026 -272.541746)
		(end 28.598876 -272.541746)
		(width 0.101854)
		(layer "F.Cu")
		(net "M_C_CPU1_SA_CB<4>")
	)
	(segment
		(start 26.459942 -272.541746)
		(end 28.529026 -272.541746)
		(width 0.1016)
		(layer "F.Cu")
		(net "M_C_CPU1_SA_CB<4>")
	)
	(segment
		(start 25.259792 -273.205448)
		(end 25.432512 -273.032728)
		(width 0.20066)
		(layer "F.Cu")
		(net "M_C_CPU1_SA_CB<4>")
	)
	(segment
		(start 95.303848 -259.081016)
		(end 95.303848 -259.616702)
		(width 0.20066)
		(layer "F.Cu")
		(net "M_C_CPU1_SA_CB<4>")
	)
	(segment
		(start 31.876746 -272.966688)
		(end 30.771846 -272.966688)
		(width 0.20066)
		(layer "F.Cu")
		(net "M_C_CPU1_SA_CB<4>")
	)
	(segment
		(start 28.977844 -272.541746)
		(end 29.402786 -272.966688)
		(width 0.20066)
		(layer "F.Cu")
		(net "M_C_CPU1_SA_CB<4>")
	)
	(segment
		(start 24.562308 -272.966688)
		(end 24.801068 -273.205448)
		(width 0.20066)
		(layer "F.Cu")
		(net "M_C_CPU1_SA_CB<4>")
	)
	(segment
		(start 25.633934 -272.541746)
		(end 26.086308 -272.541746)
		(width 0.20066)
		(layer "F.Cu")
		(net "M_C_CPU1_SA_CB<4>")
	)
	(segment
		(start 25.432512 -273.032728)
		(end 25.432512 -272.743168)
		(width 0.20066)
		(layer "F.Cu")
		(net "M_C_CPU1_SA_CB<4>")
	)
	(segment
		(start 23.228046 -272.966688)
		(end 24.562308 -272.966688)
		(width 0.20066)
		(layer "F.Cu")
		(net "M_C_CPU1_SA_CB<4>")
	)
	(segment
		(start 24.801068 -273.205448)
		(end 25.259792 -273.205448)
		(width 0.20066)
		(layer "F.Cu")
		(net "M_C_CPU1_SA_CB<4>")
	)
	(segment
		(start 29.402786 -272.966688)
		(end 30.771846 -272.966688)
		(width 0.20066)
		(layer "F.Cu")
		(net "M_C_CPU1_SA_CB<4>")
	)
	(segment
		(start 95.303848 -259.616702)
		(end 95.303594 -259.616956)
		(width 0.20066)
		(layer "F.Cu")
		(net "M_C_CPU1_SA_CB<4>")
	)
	(segment
		(start 40.822626 -268.482826)
		(end 39.984426 -269.321026)
		(width 0.18288)
		(layer "In6.Cu")
		(net "M_C_CPU1_SA_CB<4>")
	)
	(segment
		(start 64.38265 -261.676642)
		(end 64.072008 -261.676642)
		(width 0.18288)
		(layer "In6.Cu")
		(net "M_C_CPU1_SA_CB<4>")
	)
	(segment
		(start 44.226226 -265.638026)
		(end 43.335956 -265.638026)
		(width 0.18288)
		(layer "In6.Cu")
		(net "M_C_CPU1_SA_CB<4>")
	)
	(segment
		(start 42.245026 -267.670026)
		(end 41.432226 -268.482826)
		(width 0.18288)
		(layer "In6.Cu")
		(net "M_C_CPU1_SA_CB<4>")
	)
	(segment
		(start 65.39611 -261.676642)
		(end 65.23609 -261.836662)
		(width 0.18288)
		(layer "In6.Cu")
		(net "M_C_CPU1_SA_CB<4>")
	)
	(segment
		(start 64.54267 -261.836662)
		(end 64.38265 -261.676642)
		(width 0.18288)
		(layer "In6.Cu")
		(net "M_C_CPU1_SA_CB<4>")
	)
	(segment
		(start 84.429346 -259.171694)
		(end 83.885786 -259.171694)
		(width 0.088646)
		(layer "In6.Cu")
		(net "M_C_CPU1_SA_CB<4>")
	)
	(segment
		(start 90.332306 -259.121402)
		(end 90.321892 -259.127498)
		(width 0.088646)
		(layer "In6.Cu")
		(net "M_C_CPU1_SA_CB<4>")
	)
	(segment
		(start 65.23609 -261.836662)
		(end 65.23609 -262.142732)
		(width 0.18288)
		(layer "In6.Cu")
		(net "M_C_CPU1_SA_CB<4>")
	)
	(segment
		(start 66.945764 -261.676642)
		(end 65.39611 -261.676642)
		(width 0.18288)
		(layer "In6.Cu")
		(net "M_C_CPU1_SA_CB<4>")
	)
	(segment
		(start 65.07607 -262.302752)
		(end 64.70269 -262.302752)
		(width 0.18288)
		(layer "In6.Cu")
		(net "M_C_CPU1_SA_CB<4>")
	)
	(segment
		(start 55.517034 -263.502648)
		(end 54.978808 -264.040874)
		(width 0.18288)
		(layer "In6.Cu")
		(net "M_C_CPU1_SA_CB<4>")
	)
	(segment
		(start 60.215526 -264.074148)
		(end 59.631326 -264.074148)
		(width 0.18288)
		(layer "In6.Cu")
		(net "M_C_CPU1_SA_CB<4>")
	)
	(segment
		(start 41.432226 -268.482826)
		(end 40.822626 -268.482826)
		(width 0.18288)
		(layer "In6.Cu")
		(net "M_C_CPU1_SA_CB<4>")
	)
	(segment
		(start 34.962084 -270.842486)
		(end 32.837882 -272.966688)
		(width 0.18288)
		(layer "In6.Cu")
		(net "M_C_CPU1_SA_CB<4>")
	)
	(segment
		(start 46.192694 -264.890758)
		(end 45.241718 -265.841734)
		(width 0.18288)
		(layer "In6.Cu")
		(net "M_C_CPU1_SA_CB<4>")
	)
	(segment
		(start 92.216478 -259.118862)
		(end 92.201746 -259.127498)
		(width 0.088646)
		(layer "In6.Cu")
		(net "M_C_CPU1_SA_CB<4>")
	)
	(segment
		(start 44.429934 -265.841734)
		(end 44.226226 -265.638026)
		(width 0.18288)
		(layer "In6.Cu")
		(net "M_C_CPU1_SA_CB<4>")
	)
	(segment
		(start 94.738698 -259.181346)
		(end 94.646496 -259.127498)
		(width 0.088646)
		(layer "In6.Cu")
		(net "M_C_CPU1_SA_CB<4>")
	)
	(segment
		(start 43.335956 -265.638026)
		(end 42.245026 -266.728956)
		(width 0.18288)
		(layer "In6.Cu")
		(net "M_C_CPU1_SA_CB<4>")
	)
	(segment
		(start 53.184298 -263.776206)
		(end 52.91963 -264.040874)
		(width 0.18288)
		(layer "In6.Cu")
		(net "M_C_CPU1_SA_CB<4>")
	)
	(segment
		(start 39.070026 -269.321026)
		(end 37.548566 -270.842486)
		(width 0.18288)
		(layer "In6.Cu")
		(net "M_C_CPU1_SA_CB<4>")
	)
	(segment
		(start 78.005432 -261.047484)
		(end 67.574922 -261.047484)
		(width 0.18288)
		(layer "In6.Cu")
		(net "M_C_CPU1_SA_CB<4>")
	)
	(segment
		(start 94.09176 -259.121402)
		(end 94.081346 -259.127498)
		(width 0.088646)
		(layer "In6.Cu")
		(net "M_C_CPU1_SA_CB<4>")
	)
	(segment
		(start 64.54267 -262.142732)
		(end 64.54267 -261.836662)
		(width 0.18288)
		(layer "In6.Cu")
		(net "M_C_CPU1_SA_CB<4>")
	)
	(segment
		(start 65.23609 -262.142732)
		(end 65.07607 -262.302752)
		(width 0.18288)
		(layer "In6.Cu")
		(net "M_C_CPU1_SA_CB<4>")
	)
	(segment
		(start 59.631326 -264.074148)
		(end 59.059826 -263.502648)
		(width 0.18288)
		(layer "In6.Cu")
		(net "M_C_CPU1_SA_CB<4>")
	)
	(segment
		(start 59.059826 -263.502648)
		(end 55.517034 -263.502648)
		(width 0.18288)
		(layer "In6.Cu")
		(net "M_C_CPU1_SA_CB<4>")
	)
	(segment
		(start 61.688726 -262.600948)
		(end 60.215526 -264.074148)
		(width 0.18288)
		(layer "In6.Cu")
		(net "M_C_CPU1_SA_CB<4>")
	)
	(segment
		(start 42.245026 -266.728956)
		(end 42.245026 -267.670026)
		(width 0.18288)
		(layer "In6.Cu")
		(net "M_C_CPU1_SA_CB<4>")
	)
	(segment
		(start 83.885786 -259.171694)
		(end 83.297776 -259.759704)
		(width 0.088646)
		(layer "In6.Cu")
		(net "M_C_CPU1_SA_CB<4>")
	)
	(segment
		(start 81.114392 -259.759704)
		(end 78.005432 -261.047484)
		(width 0.18288)
		(layer "In6.Cu")
		(net "M_C_CPU1_SA_CB<4>")
	)
	(segment
		(start 45.241718 -265.841734)
		(end 44.429934 -265.841734)
		(width 0.18288)
		(layer "In6.Cu")
		(net "M_C_CPU1_SA_CB<4>")
	)
	(segment
		(start 47.488094 -264.890758)
		(end 46.192694 -264.890758)
		(width 0.18288)
		(layer "In6.Cu")
		(net "M_C_CPU1_SA_CB<4>")
	)
	(segment
		(start 83.297776 -259.759704)
		(end 83.088734 -259.759704)
		(width 0.088646)
		(layer "In6.Cu")
		(net "M_C_CPU1_SA_CB<4>")
	)
	(segment
		(start 67.574922 -261.047484)
		(end 66.945764 -261.676642)
		(width 0.18288)
		(layer "In6.Cu")
		(net "M_C_CPU1_SA_CB<4>")
	)
	(segment
		(start 37.548566 -270.842486)
		(end 34.962084 -270.842486)
		(width 0.18288)
		(layer "In6.Cu")
		(net "M_C_CPU1_SA_CB<4>")
	)
	(segment
		(start 63.147702 -262.600948)
		(end 61.688726 -262.600948)
		(width 0.18288)
		(layer "In6.Cu")
		(net "M_C_CPU1_SA_CB<4>")
	)
	(segment
		(start 48.337978 -264.040874)
		(end 47.488094 -264.890758)
		(width 0.18288)
		(layer "In6.Cu")
		(net "M_C_CPU1_SA_CB<4>")
	)
	(segment
		(start 32.837882 -272.966688)
		(end 31.876746 -272.966688)
		(width 0.18288)
		(layer "In6.Cu")
		(net "M_C_CPU1_SA_CB<4>")
	)
	(segment
		(start 54.978808 -264.040874)
		(end 53.852318 -264.040874)
		(width 0.18288)
		(layer "In6.Cu")
		(net "M_C_CPU1_SA_CB<4>")
	)
	(segment
		(start 64.072008 -261.676642)
		(end 63.147702 -262.600948)
		(width 0.18288)
		(layer "In6.Cu")
		(net "M_C_CPU1_SA_CB<4>")
	)
	(segment
		(start 83.088734 -259.759704)
		(end 81.114392 -259.759704)
		(width 0.18288)
		(layer "In6.Cu")
		(net "M_C_CPU1_SA_CB<4>")
	)
	(segment
		(start 52.91963 -264.040874)
		(end 48.337978 -264.040874)
		(width 0.18288)
		(layer "In6.Cu")
		(net "M_C_CPU1_SA_CB<4>")
	)
	(segment
		(start 64.70269 -262.302752)
		(end 64.54267 -262.142732)
		(width 0.18288)
		(layer "In6.Cu")
		(net "M_C_CPU1_SA_CB<4>")
	)
	(segment
		(start 93.156278 -259.118862)
		(end 93.141546 -259.127498)
		(width 0.088646)
		(layer "In6.Cu")
		(net "M_C_CPU1_SA_CB<4>")
	)
	(segment
		(start 39.984426 -269.321026)
		(end 39.070026 -269.321026)
		(width 0.18288)
		(layer "In6.Cu")
		(net "M_C_CPU1_SA_CB<4>")
	)
	(segment
		(start 53.58765 -263.776206)
		(end 53.184298 -263.776206)
		(width 0.18288)
		(layer "In6.Cu")
		(net "M_C_CPU1_SA_CB<4>")
	)
	(segment
		(start 95.303594 -259.616956)
		(end 94.738698 -259.181346)
		(width 0.088646)
		(layer "In6.Cu")
		(net "M_C_CPU1_SA_CB<4>")
	)
	(segment
		(start 53.852318 -264.040874)
		(end 53.58765 -263.776206)
		(width 0.18288)
		(layer "In6.Cu")
		(net "M_C_CPU1_SA_CB<4>")
	)
	(arc
		(start 89.947496 -259.127498)
		(mid 89.664794 -259.051722)
		(end 89.382092 -259.127498)
		(width 0.088646)
		(layer "In6.Cu")
		(net "M_C_CPU1_SA_CB<4>")
	)
	(arc
		(start 92.76715 -259.127498)
		(mid 92.492951 -259.051663)
		(end 92.216478 -259.118862)
		(width 0.088646)
		(layer "In6.Cu")
		(net "M_C_CPU1_SA_CB<4>")
	)
	(arc
		(start 90.321892 -259.127498)
		(mid 90.134694 -259.177641)
		(end 89.947496 -259.127498)
		(width 0.088646)
		(layer "In6.Cu")
		(net "M_C_CPU1_SA_CB<4>")
	)
	(arc
		(start 90.88755 -259.127498)
		(mid 90.610737 -259.051628)
		(end 90.332306 -259.121402)
		(width 0.088646)
		(layer "In6.Cu")
		(net "M_C_CPU1_SA_CB<4>")
	)
	(arc
		(start 94.081346 -259.127498)
		(mid 93.894148 -259.177641)
		(end 93.70695 -259.127498)
		(width 0.088646)
		(layer "In6.Cu")
		(net "M_C_CPU1_SA_CB<4>")
	)
	(arc
		(start 87.128096 -259.127498)
		(mid 86.845394 -259.051722)
		(end 86.562692 -259.127498)
		(width 0.088646)
		(layer "In6.Cu")
		(net "M_C_CPU1_SA_CB<4>")
	)
	(arc
		(start 87.502492 -259.127498)
		(mid 87.315294 -259.177641)
		(end 87.128096 -259.127498)
		(width 0.088646)
		(layer "In6.Cu")
		(net "M_C_CPU1_SA_CB<4>")
	)
	(arc
		(start 86.562692 -259.127498)
		(mid 86.375494 -259.177641)
		(end 86.188296 -259.127498)
		(width 0.088646)
		(layer "In6.Cu")
		(net "M_C_CPU1_SA_CB<4>")
	)
	(arc
		(start 91.82735 -259.127498)
		(mid 91.544648 -259.051722)
		(end 91.261946 -259.127498)
		(width 0.088646)
		(layer "In6.Cu")
		(net "M_C_CPU1_SA_CB<4>")
	)
	(arc
		(start 86.188296 -259.127498)
		(mid 85.905594 -259.051722)
		(end 85.622892 -259.127498)
		(width 0.088646)
		(layer "In6.Cu")
		(net "M_C_CPU1_SA_CB<4>")
	)
	(arc
		(start 84.683092 -259.127498)
		(mid 84.560138 -259.17209)
		(end 84.429346 -259.171694)
		(width 0.088646)
		(layer "In6.Cu")
		(net "M_C_CPU1_SA_CB<4>")
	)
	(arc
		(start 94.646496 -259.127498)
		(mid 94.369937 -259.051755)
		(end 94.09176 -259.121402)
		(width 0.088646)
		(layer "In6.Cu")
		(net "M_C_CPU1_SA_CB<4>")
	)
	(arc
		(start 88.067896 -259.127498)
		(mid 87.785194 -259.051722)
		(end 87.502492 -259.127498)
		(width 0.088646)
		(layer "In6.Cu")
		(net "M_C_CPU1_SA_CB<4>")
	)
	(arc
		(start 85.248496 -259.127498)
		(mid 84.965794 -259.051722)
		(end 84.683092 -259.127498)
		(width 0.088646)
		(layer "In6.Cu")
		(net "M_C_CPU1_SA_CB<4>")
	)
	(arc
		(start 93.141546 -259.127498)
		(mid 92.954348 -259.177641)
		(end 92.76715 -259.127498)
		(width 0.088646)
		(layer "In6.Cu")
		(net "M_C_CPU1_SA_CB<4>")
	)
	(arc
		(start 88.442292 -259.127498)
		(mid 88.255094 -259.177641)
		(end 88.067896 -259.127498)
		(width 0.088646)
		(layer "In6.Cu")
		(net "M_C_CPU1_SA_CB<4>")
	)
	(arc
		(start 91.261946 -259.127498)
		(mid 91.074748 -259.177641)
		(end 90.88755 -259.127498)
		(width 0.088646)
		(layer "In6.Cu")
		(net "M_C_CPU1_SA_CB<4>")
	)
	(arc
		(start 85.622892 -259.127498)
		(mid 85.435694 -259.177641)
		(end 85.248496 -259.127498)
		(width 0.088646)
		(layer "In6.Cu")
		(net "M_C_CPU1_SA_CB<4>")
	)
	(arc
		(start 89.382092 -259.127498)
		(mid 89.194894 -259.177641)
		(end 89.007696 -259.127498)
		(width 0.088646)
		(layer "In6.Cu")
		(net "M_C_CPU1_SA_CB<4>")
	)
	(arc
		(start 92.201746 -259.127498)
		(mid 92.014548 -259.177641)
		(end 91.82735 -259.127498)
		(width 0.088646)
		(layer "In6.Cu")
		(net "M_C_CPU1_SA_CB<4>")
	)
	(arc
		(start 89.007696 -259.127498)
		(mid 88.724994 -259.051722)
		(end 88.442292 -259.127498)
		(width 0.088646)
		(layer "In6.Cu")
		(net "M_C_CPU1_SA_CB<4>")
	)
	(arc
		(start 93.70695 -259.127498)
		(mid 93.432751 -259.051663)
		(end 93.156278 -259.118862)
		(width 0.088646)
		(layer "In6.Cu")
		(net "M_C_CPU1_SA_CB<4>")
	)
	(segment
		(start 32.666178 -276.642576)
		(end 32.666178 -276.43963)
		(width 0.20066)
		(layer "F.Cu")
		(net "M_C_CPU1_SA_CB<3>")
	)
	(segment
		(start 33.942274 -276.48027)
		(end 34.055812 -276.366732)
		(width 0.20066)
		(layer "F.Cu")
		(net "M_C_CPU1_SA_CB<3>")
	)
	(segment
		(start 34.055812 -276.366732)
		(end 34.871914 -276.366732)
		(width 0.20066)
		(layer "F.Cu")
		(net "M_C_CPU1_SA_CB<3>")
	)
	(segment
		(start 32.666178 -276.43963)
		(end 32.866838 -276.23897)
		(width 0.20066)
		(layer "F.Cu")
		(net "M_C_CPU1_SA_CB<3>")
	)
	(segment
		(start 33.456118 -276.48027)
		(end 33.942274 -276.48027)
		(width 0.20066)
		(layer "F.Cu")
		(net "M_C_CPU1_SA_CB<3>")
	)
	(segment
		(start 27.328114 -276.366732)
		(end 29.025342 -276.366732)
		(width 0.20066)
		(layer "F.Cu")
		(net "M_C_CPU1_SA_CB<3>")
	)
	(segment
		(start 29.899864 -276.791674)
		(end 31.972758 -276.791674)
		(width 0.1016)
		(layer "F.Cu")
		(net "M_C_CPU1_SA_CB<3>")
	)
	(segment
		(start 29.025342 -276.366732)
		(end 29.151326 -276.492716)
		(width 0.20066)
		(layer "F.Cu")
		(net "M_C_CPU1_SA_CB<3>")
	)
	(segment
		(start 29.29382 -276.791674)
		(end 29.520896 -276.791674)
		(width 0.20066)
		(layer "F.Cu")
		(net "M_C_CPU1_SA_CB<3>")
	)
	(segment
		(start 29.151326 -276.492716)
		(end 29.151326 -276.64918)
		(width 0.20066)
		(layer "F.Cu")
		(net "M_C_CPU1_SA_CB<3>")
	)
	(segment
		(start 97.183448 -260.708902)
		(end 97.183448 -261.244588)
		(width 0.20066)
		(layer "F.Cu")
		(net "M_C_CPU1_SA_CB<3>")
	)
	(segment
		(start 31.972758 -276.791674)
		(end 32.045656 -276.791674)
		(width 0.101854)
		(layer "F.Cu")
		(net "M_C_CPU1_SA_CB<3>")
	)
	(segment
		(start 29.151326 -276.64918)
		(end 29.29382 -276.791674)
		(width 0.20066)
		(layer "F.Cu")
		(net "M_C_CPU1_SA_CB<3>")
	)
	(segment
		(start 33.214818 -276.23897)
		(end 33.456118 -276.48027)
		(width 0.20066)
		(layer "F.Cu")
		(net "M_C_CPU1_SA_CB<3>")
	)
	(segment
		(start 32.045656 -276.791674)
		(end 32.51708 -276.791674)
		(width 0.20066)
		(layer "F.Cu")
		(net "M_C_CPU1_SA_CB<3>")
	)
	(segment
		(start 32.51708 -276.791674)
		(end 32.666178 -276.642576)
		(width 0.20066)
		(layer "F.Cu")
		(net "M_C_CPU1_SA_CB<3>")
	)
	(segment
		(start 32.866838 -276.23897)
		(end 33.214818 -276.23897)
		(width 0.20066)
		(layer "F.Cu")
		(net "M_C_CPU1_SA_CB<3>")
	)
	(segment
		(start 35.976814 -276.366732)
		(end 34.871914 -276.366732)
		(width 0.20066)
		(layer "F.Cu")
		(net "M_C_CPU1_SA_CB<3>")
	)
	(segment
		(start 29.520896 -276.791674)
		(end 29.899864 -276.791674)
		(width 0.101854)
		(layer "F.Cu")
		(net "M_C_CPU1_SA_CB<3>")
	)
	(segment
		(start 97.183448 -261.244588)
		(end 97.183194 -261.244842)
		(width 0.20066)
		(layer "F.Cu")
		(net "M_C_CPU1_SA_CB<3>")
	)
	(segment
		(start 72.819768 -264.21588)
		(end 67.483228 -266.426188)
		(width 0.18288)
		(layer "In6.Cu")
		(net "M_C_CPU1_SA_CB<3>")
	)
	(segment
		(start 53.860446 -269.668244)
		(end 53.677566 -269.851124)
		(width 0.18288)
		(layer "In6.Cu")
		(net "M_C_CPU1_SA_CB<3>")
	)
	(segment
		(start 64.400938 -268.856714)
		(end 63.250826 -268.856714)
		(width 0.18288)
		(layer "In6.Cu")
		(net "M_C_CPU1_SA_CB<3>")
	)
	(segment
		(start 57.56529 -269.793212)
		(end 57.24017 -269.793212)
		(width 0.18288)
		(layer "In6.Cu")
		(net "M_C_CPU1_SA_CB<3>")
	)
	(segment
		(start 52.803806 -269.668244)
		(end 52.112926 -269.668244)
		(width 0.18288)
		(layer "In6.Cu")
		(net "M_C_CPU1_SA_CB<3>")
	)
	(segment
		(start 53.677566 -270.157448)
		(end 53.494686 -270.340328)
		(width 0.18288)
		(layer "In6.Cu")
		(net "M_C_CPU1_SA_CB<3>")
	)
	(segment
		(start 83.913726 -261.809992)
		(end 83.685888 -262.03783)
		(width 0.088646)
		(layer "In6.Cu")
		(net "M_C_CPU1_SA_CB<3>")
	)
	(segment
		(start 67.483228 -266.426188)
		(end 66.4845 -267.424916)
		(width 0.18288)
		(layer "In6.Cu")
		(net "M_C_CPU1_SA_CB<3>")
	)
	(segment
		(start 57.74817 -269.090394)
		(end 57.74817 -269.610332)
		(width 0.18288)
		(layer "In6.Cu")
		(net "M_C_CPU1_SA_CB<3>")
	)
	(segment
		(start 56.18353 -268.907514)
		(end 55.4228 -269.668244)
		(width 0.18288)
		(layer "In6.Cu")
		(net "M_C_CPU1_SA_CB<3>")
	)
	(segment
		(start 88.452706 -261.740396)
		(end 88.442292 -261.7343)
		(width 0.088646)
		(layer "In6.Cu")
		(net "M_C_CPU1_SA_CB<3>")
	)
	(segment
		(start 52.986686 -269.851124)
		(end 52.803806 -269.668244)
		(width 0.18288)
		(layer "In6.Cu")
		(net "M_C_CPU1_SA_CB<3>")
	)
	(segment
		(start 62.666626 -268.272514)
		(end 61.84265 -268.272514)
		(width 0.18288)
		(layer "In6.Cu")
		(net "M_C_CPU1_SA_CB<3>")
	)
	(segment
		(start 60.524644 -269.578074)
		(end 60.357004 -269.745714)
		(width 0.18288)
		(layer "In6.Cu")
		(net "M_C_CPU1_SA_CB<3>")
	)
	(segment
		(start 83.685888 -262.510016)
		(end 83.298792 -262.897112)
		(width 0.088646)
		(layer "In6.Cu")
		(net "M_C_CPU1_SA_CB<3>")
	)
	(segment
		(start 58.900314 -268.907514)
		(end 57.93105 -268.907514)
		(width 0.18288)
		(layer "In6.Cu")
		(net "M_C_CPU1_SA_CB<3>")
	)
	(segment
		(start 61.84265 -268.272514)
		(end 61.253878 -268.861286)
		(width 0.18288)
		(layer "In6.Cu")
		(net "M_C_CPU1_SA_CB<3>")
	)
	(segment
		(start 52.986686 -270.157448)
		(end 52.986686 -269.851124)
		(width 0.18288)
		(layer "In6.Cu")
		(net "M_C_CPU1_SA_CB<3>")
	)
	(segment
		(start 83.685888 -262.03783)
		(end 83.685888 -262.510016)
		(width 0.088646)
		(layer "In6.Cu")
		(net "M_C_CPU1_SA_CB<3>")
	)
	(segment
		(start 82.658204 -262.897112)
		(end 81.667858 -262.897112)
		(width 0.18288)
		(layer "In6.Cu")
		(net "M_C_CPU1_SA_CB<3>")
	)
	(segment
		(start 43.190414 -272.541238)
		(end 41.516046 -274.215606)
		(width 0.18288)
		(layer "In6.Cu")
		(net "M_C_CPU1_SA_CB<3>")
	)
	(segment
		(start 56.87441 -268.907514)
		(end 56.18353 -268.907514)
		(width 0.18288)
		(layer "In6.Cu")
		(net "M_C_CPU1_SA_CB<3>")
	)
	(segment
		(start 95.975678 -261.742936)
		(end 95.960946 -261.7343)
		(width 0.088646)
		(layer "In6.Cu")
		(net "M_C_CPU1_SA_CB<3>")
	)
	(segment
		(start 65.832736 -267.424916)
		(end 64.400938 -268.856714)
		(width 0.18288)
		(layer "In6.Cu")
		(net "M_C_CPU1_SA_CB<3>")
	)
	(segment
		(start 89.39276 -261.740396)
		(end 89.382346 -261.7343)
		(width 0.088646)
		(layer "In6.Cu")
		(net "M_C_CPU1_SA_CB<3>")
	)
	(segment
		(start 52.112926 -269.668244)
		(end 51.790346 -269.990824)
		(width 0.18288)
		(layer "In6.Cu")
		(net "M_C_CPU1_SA_CB<3>")
	)
	(segment
		(start 38.739826 -274.909026)
		(end 37.927026 -275.721826)
		(width 0.18288)
		(layer "In6.Cu")
		(net "M_C_CPU1_SA_CB<3>")
	)
	(segment
		(start 91.272106 -261.740396)
		(end 91.261692 -261.7343)
		(width 0.088646)
		(layer "In6.Cu")
		(net "M_C_CPU1_SA_CB<3>")
	)
	(segment
		(start 78.483968 -264.21588)
		(end 72.819768 -264.21588)
		(width 0.18288)
		(layer "In6.Cu")
		(net "M_C_CPU1_SA_CB<3>")
	)
	(segment
		(start 92.216478 -261.742936)
		(end 92.201746 -261.7343)
		(width 0.088646)
		(layer "In6.Cu")
		(net "M_C_CPU1_SA_CB<3>")
	)
	(segment
		(start 63.250826 -268.856714)
		(end 62.666626 -268.272514)
		(width 0.18288)
		(layer "In6.Cu")
		(net "M_C_CPU1_SA_CB<3>")
	)
	(segment
		(start 53.494686 -270.340328)
		(end 53.169566 -270.340328)
		(width 0.18288)
		(layer "In6.Cu")
		(net "M_C_CPU1_SA_CB<3>")
	)
	(segment
		(start 95.035878 -261.742936)
		(end 95.021146 -261.7343)
		(width 0.088646)
		(layer "In6.Cu")
		(net "M_C_CPU1_SA_CB<3>")
	)
	(segment
		(start 53.677566 -269.851124)
		(end 53.677566 -270.157448)
		(width 0.18288)
		(layer "In6.Cu")
		(net "M_C_CPU1_SA_CB<3>")
	)
	(segment
		(start 60.524644 -269.044166)
		(end 60.524644 -269.578074)
		(width 0.18288)
		(layer "In6.Cu")
		(net "M_C_CPU1_SA_CB<3>")
	)
	(segment
		(start 93.156278 -261.742936)
		(end 93.141546 -261.7343)
		(width 0.088646)
		(layer "In6.Cu")
		(net "M_C_CPU1_SA_CB<3>")
	)
	(segment
		(start 84.025994 -261.809992)
		(end 83.913726 -261.809992)
		(width 0.088646)
		(layer "In6.Cu")
		(net "M_C_CPU1_SA_CB<3>")
	)
	(segment
		(start 36.62172 -275.721826)
		(end 35.976814 -276.366732)
		(width 0.18288)
		(layer "In6.Cu")
		(net "M_C_CPU1_SA_CB<3>")
	)
	(segment
		(start 53.169566 -270.340328)
		(end 52.986686 -270.157448)
		(width 0.18288)
		(layer "In6.Cu")
		(net "M_C_CPU1_SA_CB<3>")
	)
	(segment
		(start 57.05729 -269.090394)
		(end 56.87441 -268.907514)
		(width 0.18288)
		(layer "In6.Cu")
		(net "M_C_CPU1_SA_CB<3>")
	)
	(segment
		(start 41.516046 -274.215606)
		(end 40.533066 -274.215606)
		(width 0.18288)
		(layer "In6.Cu")
		(net "M_C_CPU1_SA_CB<3>")
	)
	(segment
		(start 81.667858 -262.897112)
		(end 78.483968 -264.21588)
		(width 0.18288)
		(layer "In6.Cu")
		(net "M_C_CPU1_SA_CB<3>")
	)
	(segment
		(start 66.4845 -267.424916)
		(end 65.832736 -267.424916)
		(width 0.18288)
		(layer "In6.Cu")
		(net "M_C_CPU1_SA_CB<3>")
	)
	(segment
		(start 39.839646 -274.909026)
		(end 38.739826 -274.909026)
		(width 0.18288)
		(layer "In6.Cu")
		(net "M_C_CPU1_SA_CB<3>")
	)
	(segment
		(start 57.24017 -269.793212)
		(end 57.05729 -269.610332)
		(width 0.18288)
		(layer "In6.Cu")
		(net "M_C_CPU1_SA_CB<3>")
	)
	(segment
		(start 48.254666 -272.541238)
		(end 43.190414 -272.541238)
		(width 0.18288)
		(layer "In6.Cu")
		(net "M_C_CPU1_SA_CB<3>")
	)
	(segment
		(start 61.253878 -268.861286)
		(end 60.707524 -268.861286)
		(width 0.18288)
		(layer "In6.Cu")
		(net "M_C_CPU1_SA_CB<3>")
	)
	(segment
		(start 51.790346 -269.990824)
		(end 50.80508 -269.990824)
		(width 0.18288)
		(layer "In6.Cu")
		(net "M_C_CPU1_SA_CB<3>")
	)
	(segment
		(start 60.707524 -268.861286)
		(end 60.524644 -269.044166)
		(width 0.18288)
		(layer "In6.Cu")
		(net "M_C_CPU1_SA_CB<3>")
	)
	(segment
		(start 50.80508 -269.990824)
		(end 48.254666 -272.541238)
		(width 0.18288)
		(layer "In6.Cu")
		(net "M_C_CPU1_SA_CB<3>")
	)
	(segment
		(start 55.4228 -269.668244)
		(end 53.860446 -269.668244)
		(width 0.18288)
		(layer "In6.Cu")
		(net "M_C_CPU1_SA_CB<3>")
	)
	(segment
		(start 57.05729 -269.610332)
		(end 57.05729 -269.090394)
		(width 0.18288)
		(layer "In6.Cu")
		(net "M_C_CPU1_SA_CB<3>")
	)
	(segment
		(start 57.93105 -268.907514)
		(end 57.74817 -269.090394)
		(width 0.18288)
		(layer "In6.Cu")
		(net "M_C_CPU1_SA_CB<3>")
	)
	(segment
		(start 60.357004 -269.745714)
		(end 59.738514 -269.745714)
		(width 0.18288)
		(layer "In6.Cu")
		(net "M_C_CPU1_SA_CB<3>")
	)
	(segment
		(start 40.533066 -274.215606)
		(end 39.839646 -274.909026)
		(width 0.18288)
		(layer "In6.Cu")
		(net "M_C_CPU1_SA_CB<3>")
	)
	(segment
		(start 57.74817 -269.610332)
		(end 57.56529 -269.793212)
		(width 0.18288)
		(layer "In6.Cu")
		(net "M_C_CPU1_SA_CB<3>")
	)
	(segment
		(start 59.738514 -269.745714)
		(end 58.900314 -268.907514)
		(width 0.18288)
		(layer "In6.Cu")
		(net "M_C_CPU1_SA_CB<3>")
	)
	(segment
		(start 94.096078 -261.742936)
		(end 94.081346 -261.7343)
		(width 0.088646)
		(layer "In6.Cu")
		(net "M_C_CPU1_SA_CB<3>")
	)
	(segment
		(start 83.298792 -262.897112)
		(end 82.658204 -262.897112)
		(width 0.088646)
		(layer "In6.Cu")
		(net "M_C_CPU1_SA_CB<3>")
	)
	(segment
		(start 37.927026 -275.721826)
		(end 36.62172 -275.721826)
		(width 0.18288)
		(layer "In6.Cu")
		(net "M_C_CPU1_SA_CB<3>")
	)
	(arc
		(start 90.887296 -261.7343)
		(mid 90.604594 -261.810076)
		(end 90.321892 -261.7343)
		(width 0.088646)
		(layer "In6.Cu")
		(net "M_C_CPU1_SA_CB<3>")
	)
	(arc
		(start 84.683092 -261.7343)
		(mid 84.495894 -261.684157)
		(end 84.308696 -261.7343)
		(width 0.088646)
		(layer "In6.Cu")
		(net "M_C_CPU1_SA_CB<3>")
	)
	(arc
		(start 94.64675 -261.7343)
		(mid 94.372551 -261.810135)
		(end 94.096078 -261.742936)
		(width 0.088646)
		(layer "In6.Cu")
		(net "M_C_CPU1_SA_CB<3>")
	)
	(arc
		(start 86.188296 -261.7343)
		(mid 85.905594 -261.810076)
		(end 85.622892 -261.7343)
		(width 0.088646)
		(layer "In6.Cu")
		(net "M_C_CPU1_SA_CB<3>")
	)
	(arc
		(start 85.248496 -261.7343)
		(mid 84.965794 -261.810076)
		(end 84.683092 -261.7343)
		(width 0.088646)
		(layer "In6.Cu")
		(net "M_C_CPU1_SA_CB<3>")
	)
	(arc
		(start 93.70695 -261.7343)
		(mid 93.432751 -261.810135)
		(end 93.156278 -261.742936)
		(width 0.088646)
		(layer "In6.Cu")
		(net "M_C_CPU1_SA_CB<3>")
	)
	(arc
		(start 97.183194 -261.244842)
		(mid 96.869017 -261.508688)
		(end 96.52635 -261.7343)
		(width 0.088646)
		(layer "In6.Cu")
		(net "M_C_CPU1_SA_CB<3>")
	)
	(arc
		(start 89.947496 -261.7343)
		(mid 89.670937 -261.810043)
		(end 89.39276 -261.740396)
		(width 0.088646)
		(layer "In6.Cu")
		(net "M_C_CPU1_SA_CB<3>")
	)
	(arc
		(start 96.52635 -261.7343)
		(mid 96.252151 -261.810135)
		(end 95.975678 -261.742936)
		(width 0.088646)
		(layer "In6.Cu")
		(net "M_C_CPU1_SA_CB<3>")
	)
	(arc
		(start 92.76715 -261.7343)
		(mid 92.492951 -261.810135)
		(end 92.216478 -261.742936)
		(width 0.088646)
		(layer "In6.Cu")
		(net "M_C_CPU1_SA_CB<3>")
	)
	(arc
		(start 91.261692 -261.7343)
		(mid 91.074494 -261.684157)
		(end 90.887296 -261.7343)
		(width 0.088646)
		(layer "In6.Cu")
		(net "M_C_CPU1_SA_CB<3>")
	)
	(arc
		(start 95.960946 -261.7343)
		(mid 95.773748 -261.684157)
		(end 95.58655 -261.7343)
		(width 0.088646)
		(layer "In6.Cu")
		(net "M_C_CPU1_SA_CB<3>")
	)
	(arc
		(start 94.081346 -261.7343)
		(mid 93.894148 -261.684157)
		(end 93.70695 -261.7343)
		(width 0.088646)
		(layer "In6.Cu")
		(net "M_C_CPU1_SA_CB<3>")
	)
	(arc
		(start 88.067896 -261.7343)
		(mid 87.785194 -261.810076)
		(end 87.502492 -261.7343)
		(width 0.088646)
		(layer "In6.Cu")
		(net "M_C_CPU1_SA_CB<3>")
	)
	(arc
		(start 85.622892 -261.7343)
		(mid 85.435694 -261.684157)
		(end 85.248496 -261.7343)
		(width 0.088646)
		(layer "In6.Cu")
		(net "M_C_CPU1_SA_CB<3>")
	)
	(arc
		(start 89.382346 -261.7343)
		(mid 89.195148 -261.684123)
		(end 89.00795 -261.7343)
		(width 0.088646)
		(layer "In6.Cu")
		(net "M_C_CPU1_SA_CB<3>")
	)
	(arc
		(start 92.201746 -261.7343)
		(mid 92.014548 -261.684157)
		(end 91.82735 -261.7343)
		(width 0.088646)
		(layer "In6.Cu")
		(net "M_C_CPU1_SA_CB<3>")
	)
	(arc
		(start 86.562692 -261.7343)
		(mid 86.375494 -261.684157)
		(end 86.188296 -261.7343)
		(width 0.088646)
		(layer "In6.Cu")
		(net "M_C_CPU1_SA_CB<3>")
	)
	(arc
		(start 84.308696 -261.7343)
		(mid 84.172327 -261.790742)
		(end 84.025994 -261.809992)
		(width 0.088646)
		(layer "In6.Cu")
		(net "M_C_CPU1_SA_CB<3>")
	)
	(arc
		(start 87.502492 -261.7343)
		(mid 87.315294 -261.684157)
		(end 87.128096 -261.7343)
		(width 0.088646)
		(layer "In6.Cu")
		(net "M_C_CPU1_SA_CB<3>")
	)
	(arc
		(start 93.141546 -261.7343)
		(mid 92.954348 -261.684157)
		(end 92.76715 -261.7343)
		(width 0.088646)
		(layer "In6.Cu")
		(net "M_C_CPU1_SA_CB<3>")
	)
	(arc
		(start 95.021146 -261.7343)
		(mid 94.833948 -261.684157)
		(end 94.64675 -261.7343)
		(width 0.088646)
		(layer "In6.Cu")
		(net "M_C_CPU1_SA_CB<3>")
	)
	(arc
		(start 90.321892 -261.7343)
		(mid 90.134694 -261.684157)
		(end 89.947496 -261.7343)
		(width 0.088646)
		(layer "In6.Cu")
		(net "M_C_CPU1_SA_CB<3>")
	)
	(arc
		(start 89.00795 -261.7343)
		(mid 88.731137 -261.81017)
		(end 88.452706 -261.740396)
		(width 0.088646)
		(layer "In6.Cu")
		(net "M_C_CPU1_SA_CB<3>")
	)
	(arc
		(start 95.58655 -261.7343)
		(mid 95.312351 -261.810135)
		(end 95.035878 -261.742936)
		(width 0.088646)
		(layer "In6.Cu")
		(net "M_C_CPU1_SA_CB<3>")
	)
	(arc
		(start 87.128096 -261.7343)
		(mid 86.845394 -261.810076)
		(end 86.562692 -261.7343)
		(width 0.088646)
		(layer "In6.Cu")
		(net "M_C_CPU1_SA_CB<3>")
	)
	(arc
		(start 88.442292 -261.7343)
		(mid 88.255094 -261.684157)
		(end 88.067896 -261.7343)
		(width 0.088646)
		(layer "In6.Cu")
		(net "M_C_CPU1_SA_CB<3>")
	)
	(arc
		(start 91.82735 -261.7343)
		(mid 91.550537 -261.81017)
		(end 91.272106 -261.740396)
		(width 0.088646)
		(layer "In6.Cu")
		(net "M_C_CPU1_SA_CB<3>")
	)
	(segment
		(start 96.713294 -261.522718)
		(end 96.713294 -262.058404)
		(width 0.20066)
		(layer "F.Cu")
		(net "M_C_CPU1_SA_CB<2>")
	)
	(segment
		(start 28.90012 -277.641812)
		(end 29.51607 -277.641812)
		(width 0.20066)
		(layer "F.Cu")
		(net "M_C_CPU1_SA_CB<2>")
	)
	(segment
		(start 29.51607 -277.641812)
		(end 29.912818 -277.641812)
		(width 0.101854)
		(layer "F.Cu")
		(net "M_C_CPU1_SA_CB<2>")
	)
	(segment
		(start 32.58185 -277.641812)
		(end 32.74949 -277.809452)
		(width 0.20066)
		(layer "F.Cu")
		(net "M_C_CPU1_SA_CB<2>")
	)
	(segment
		(start 32.74949 -277.809452)
		(end 32.74949 -278.111204)
		(width 0.20066)
		(layer "F.Cu")
		(net "M_C_CPU1_SA_CB<2>")
	)
	(segment
		(start 32.04464 -277.641812)
		(end 32.58185 -277.641812)
		(width 0.20066)
		(layer "F.Cu")
		(net "M_C_CPU1_SA_CB<2>")
	)
	(segment
		(start 96.713294 -262.058404)
		(end 96.713548 -262.058658)
		(width 0.20066)
		(layer "F.Cu")
		(net "M_C_CPU1_SA_CB<2>")
	)
	(segment
		(start 29.912818 -277.641812)
		(end 32.010604 -277.641812)
		(width 0.1016)
		(layer "F.Cu")
		(net "M_C_CPU1_SA_CB<2>")
	)
	(segment
		(start 33.55721 -278.066754)
		(end 34.871914 -278.066754)
		(width 0.20066)
		(layer "F.Cu")
		(net "M_C_CPU1_SA_CB<2>")
	)
	(segment
		(start 32.74949 -278.111204)
		(end 32.947356 -278.30907)
		(width 0.20066)
		(layer "F.Cu")
		(net "M_C_CPU1_SA_CB<2>")
	)
	(segment
		(start 28.475178 -278.066754)
		(end 28.90012 -277.641812)
		(width 0.20066)
		(layer "F.Cu")
		(net "M_C_CPU1_SA_CB<2>")
	)
	(segment
		(start 32.010604 -277.641812)
		(end 32.04464 -277.641812)
		(width 0.101854)
		(layer "F.Cu")
		(net "M_C_CPU1_SA_CB<2>")
	)
	(segment
		(start 27.328114 -278.066754)
		(end 28.475178 -278.066754)
		(width 0.20066)
		(layer "F.Cu")
		(net "M_C_CPU1_SA_CB<2>")
	)
	(segment
		(start 33.314894 -278.30907)
		(end 33.55721 -278.066754)
		(width 0.20066)
		(layer "F.Cu")
		(net "M_C_CPU1_SA_CB<2>")
	)
	(segment
		(start 35.976814 -278.066754)
		(end 34.871914 -278.066754)
		(width 0.20066)
		(layer "F.Cu")
		(net "M_C_CPU1_SA_CB<2>")
	)
	(segment
		(start 32.947356 -278.30907)
		(end 33.314894 -278.30907)
		(width 0.20066)
		(layer "F.Cu")
		(net "M_C_CPU1_SA_CB<2>")
	)
	(segment
		(start 52.902866 -271.873726)
		(end 52.719986 -271.690846)
		(width 0.18288)
		(layer "In6.Cu")
		(net "M_C_CPU1_SA_CB<2>")
	)
	(segment
		(start 83.188048 -263.919208)
		(end 82.658204 -263.919208)
		(width 0.088646)
		(layer "In6.Cu")
		(net "M_C_CPU1_SA_CB<2>")
	)
	(segment
		(start 61.85916 -269.992602)
		(end 60.406026 -271.445736)
		(width 0.18288)
		(layer "In6.Cu")
		(net "M_C_CPU1_SA_CB<2>")
	)
	(segment
		(start 96.062292 -262.54456)
		(end 96.056196 -262.548116)
		(width 0.088646)
		(layer "In6.Cu")
		(net "M_C_CPU1_SA_CB<2>")
	)
	(segment
		(start 53.085746 -272.580862)
		(end 52.902866 -272.397982)
		(width 0.18288)
		(layer "In6.Cu")
		(net "M_C_CPU1_SA_CB<2>")
	)
	(segment
		(start 81.803494 -263.919208)
		(end 78.63205 -265.232642)
		(width 0.18288)
		(layer "In6.Cu")
		(net "M_C_CPU1_SA_CB<2>")
	)
	(segment
		(start 45.10532 -274.24126)
		(end 44.92244 -274.42414)
		(width 0.18288)
		(layer "In6.Cu")
		(net "M_C_CPU1_SA_CB<2>")
	)
	(segment
		(start 49.234852 -274.24126)
		(end 45.10532 -274.24126)
		(width 0.18288)
		(layer "In6.Cu")
		(net "M_C_CPU1_SA_CB<2>")
	)
	(segment
		(start 89.862406 -262.554212)
		(end 89.851992 -262.548116)
		(width 0.088646)
		(layer "In6.Cu")
		(net "M_C_CPU1_SA_CB<2>")
	)
	(segment
		(start 73.355962 -265.232642)
		(end 68.263262 -267.34135)
		(width 0.18288)
		(layer "In6.Cu")
		(net "M_C_CPU1_SA_CB<2>")
	)
	(segment
		(start 53.593746 -272.397982)
		(end 53.410866 -272.580862)
		(width 0.18288)
		(layer "In6.Cu")
		(net "M_C_CPU1_SA_CB<2>")
	)
	(segment
		(start 50.78476 -271.690846)
		(end 50.316384 -272.159222)
		(width 0.18288)
		(layer "In6.Cu")
		(net "M_C_CPU1_SA_CB<2>")
	)
	(segment
		(start 96.713548 -262.058658)
		(end 96.400874 -262.058658)
		(width 0.088646)
		(layer "In6.Cu")
		(net "M_C_CPU1_SA_CB<2>")
	)
	(segment
		(start 43.319192 -274.24126)
		(end 42.166286 -275.394166)
		(width 0.18288)
		(layer "In6.Cu")
		(net "M_C_CPU1_SA_CB<2>")
	)
	(segment
		(start 42.559478 -276.04593)
		(end 42.559478 -276.304502)
		(width 0.18288)
		(layer "In6.Cu")
		(net "M_C_CPU1_SA_CB<2>")
	)
	(segment
		(start 53.593746 -271.873726)
		(end 53.593746 -272.397982)
		(width 0.18288)
		(layer "In6.Cu")
		(net "M_C_CPU1_SA_CB<2>")
	)
	(segment
		(start 92.296996 -262.548116)
		(end 92.282264 -262.556752)
		(width 0.088646)
		(layer "In6.Cu")
		(net "M_C_CPU1_SA_CB<2>")
	)
	(segment
		(start 96.400874 -262.058658)
		(end 96.335088 -262.124444)
		(width 0.088646)
		(layer "In6.Cu")
		(net "M_C_CPU1_SA_CB<2>")
	)
	(segment
		(start 44.41444 -275.038566)
		(end 44.23156 -274.855686)
		(width 0.18288)
		(layer "In6.Cu")
		(net "M_C_CPU1_SA_CB<2>")
	)
	(segment
		(start 44.73956 -275.038566)
		(end 44.41444 -275.038566)
		(width 0.18288)
		(layer "In6.Cu")
		(net "M_C_CPU1_SA_CB<2>")
	)
	(segment
		(start 42.166286 -275.652738)
		(end 42.559478 -276.04593)
		(width 0.18288)
		(layer "In6.Cu")
		(net "M_C_CPU1_SA_CB<2>")
	)
	(segment
		(start 78.63205 -265.232642)
		(end 73.355962 -265.232642)
		(width 0.18288)
		(layer "In6.Cu")
		(net "M_C_CPU1_SA_CB<2>")
	)
	(segment
		(start 42.329354 -276.534626)
		(end 42.070782 -276.534626)
		(width 0.18288)
		(layer "In6.Cu")
		(net "M_C_CPU1_SA_CB<2>")
	)
	(segment
		(start 96.056196 -262.548116)
		(end 96.041464 -262.556752)
		(width 0.088646)
		(layer "In6.Cu")
		(net "M_C_CPU1_SA_CB<2>")
	)
	(segment
		(start 95.116396 -262.548116)
		(end 95.101664 -262.556752)
		(width 0.088646)
		(layer "In6.Cu")
		(net "M_C_CPU1_SA_CB<2>")
	)
	(segment
		(start 39.88816 -276.630892)
		(end 39.00424 -277.514812)
		(width 0.18288)
		(layer "In6.Cu")
		(net "M_C_CPU1_SA_CB<2>")
	)
	(segment
		(start 90.80246 -262.554212)
		(end 90.792046 -262.548116)
		(width 0.088646)
		(layer "In6.Cu")
		(net "M_C_CPU1_SA_CB<2>")
	)
	(segment
		(start 93.236796 -262.548116)
		(end 93.222064 -262.556752)
		(width 0.088646)
		(layer "In6.Cu")
		(net "M_C_CPU1_SA_CB<2>")
	)
	(segment
		(start 41.419018 -276.141434)
		(end 40.92956 -276.630892)
		(width 0.18288)
		(layer "In6.Cu")
		(net "M_C_CPU1_SA_CB<2>")
	)
	(segment
		(start 84.345526 -262.76173)
		(end 83.188048 -263.919208)
		(width 0.088646)
		(layer "In6.Cu")
		(net "M_C_CPU1_SA_CB<2>")
	)
	(segment
		(start 53.776626 -271.690846)
		(end 53.593746 -271.873726)
		(width 0.18288)
		(layer "In6.Cu")
		(net "M_C_CPU1_SA_CB<2>")
	)
	(segment
		(start 53.410866 -272.580862)
		(end 53.085746 -272.580862)
		(width 0.18288)
		(layer "In6.Cu")
		(net "M_C_CPU1_SA_CB<2>")
	)
	(segment
		(start 64.450976 -270.575786)
		(end 63.143892 -270.575786)
		(width 0.18288)
		(layer "In6.Cu")
		(net "M_C_CPU1_SA_CB<2>")
	)
	(segment
		(start 82.658204 -263.919208)
		(end 81.803494 -263.919208)
		(width 0.18288)
		(layer "In6.Cu")
		(net "M_C_CPU1_SA_CB<2>")
	)
	(segment
		(start 44.92244 -274.42414)
		(end 44.92244 -274.855686)
		(width 0.18288)
		(layer "In6.Cu")
		(net "M_C_CPU1_SA_CB<2>")
	)
	(segment
		(start 50.316384 -272.159222)
		(end 50.316384 -273.159728)
		(width 0.18288)
		(layer "In6.Cu")
		(net "M_C_CPU1_SA_CB<2>")
	)
	(segment
		(start 63.143892 -270.575786)
		(end 62.560708 -269.992602)
		(width 0.18288)
		(layer "In6.Cu")
		(net "M_C_CPU1_SA_CB<2>")
	)
	(segment
		(start 54.852316 -271.690846)
		(end 53.776626 -271.690846)
		(width 0.18288)
		(layer "In6.Cu")
		(net "M_C_CPU1_SA_CB<2>")
	)
	(segment
		(start 40.92956 -276.630892)
		(end 39.88816 -276.630892)
		(width 0.18288)
		(layer "In6.Cu")
		(net "M_C_CPU1_SA_CB<2>")
	)
	(segment
		(start 44.23156 -274.855686)
		(end 44.23156 -274.42414)
		(width 0.18288)
		(layer "In6.Cu")
		(net "M_C_CPU1_SA_CB<2>")
	)
	(segment
		(start 44.04868 -274.24126)
		(end 43.319192 -274.24126)
		(width 0.18288)
		(layer "In6.Cu")
		(net "M_C_CPU1_SA_CB<2>")
	)
	(segment
		(start 59.440826 -271.445736)
		(end 58.805826 -270.810736)
		(width 0.18288)
		(layer "In6.Cu")
		(net "M_C_CPU1_SA_CB<2>")
	)
	(segment
		(start 44.92244 -274.855686)
		(end 44.73956 -275.038566)
		(width 0.18288)
		(layer "In6.Cu")
		(net "M_C_CPU1_SA_CB<2>")
	)
	(segment
		(start 42.559478 -276.304502)
		(end 42.329354 -276.534626)
		(width 0.18288)
		(layer "In6.Cu")
		(net "M_C_CPU1_SA_CB<2>")
	)
	(segment
		(start 94.176596 -262.548116)
		(end 94.161864 -262.556752)
		(width 0.088646)
		(layer "In6.Cu")
		(net "M_C_CPU1_SA_CB<2>")
	)
	(segment
		(start 50.316384 -273.159728)
		(end 49.234852 -274.24126)
		(width 0.18288)
		(layer "In6.Cu")
		(net "M_C_CPU1_SA_CB<2>")
	)
	(segment
		(start 60.406026 -271.445736)
		(end 59.440826 -271.445736)
		(width 0.18288)
		(layer "In6.Cu")
		(net "M_C_CPU1_SA_CB<2>")
	)
	(segment
		(start 36.528756 -277.514812)
		(end 35.976814 -278.066754)
		(width 0.18288)
		(layer "In6.Cu")
		(net "M_C_CPU1_SA_CB<2>")
	)
	(segment
		(start 65.882774 -269.143988)
		(end 64.450976 -270.575786)
		(width 0.18288)
		(layer "In6.Cu")
		(net "M_C_CPU1_SA_CB<2>")
	)
	(segment
		(start 44.23156 -274.42414)
		(end 44.04868 -274.24126)
		(width 0.18288)
		(layer "In6.Cu")
		(net "M_C_CPU1_SA_CB<2>")
	)
	(segment
		(start 58.805826 -270.810736)
		(end 55.732426 -270.810736)
		(width 0.18288)
		(layer "In6.Cu")
		(net "M_C_CPU1_SA_CB<2>")
	)
	(segment
		(start 42.166286 -275.394166)
		(end 42.166286 -275.652738)
		(width 0.18288)
		(layer "In6.Cu")
		(net "M_C_CPU1_SA_CB<2>")
	)
	(segment
		(start 62.560708 -269.992602)
		(end 61.85916 -269.992602)
		(width 0.18288)
		(layer "In6.Cu")
		(net "M_C_CPU1_SA_CB<2>")
	)
	(segment
		(start 52.902866 -272.397982)
		(end 52.902866 -271.873726)
		(width 0.18288)
		(layer "In6.Cu")
		(net "M_C_CPU1_SA_CB<2>")
	)
	(segment
		(start 55.732426 -270.810736)
		(end 54.852316 -271.690846)
		(width 0.18288)
		(layer "In6.Cu")
		(net "M_C_CPU1_SA_CB<2>")
	)
	(segment
		(start 52.719986 -271.690846)
		(end 50.78476 -271.690846)
		(width 0.18288)
		(layer "In6.Cu")
		(net "M_C_CPU1_SA_CB<2>")
	)
	(segment
		(start 39.00424 -277.514812)
		(end 36.528756 -277.514812)
		(width 0.18288)
		(layer "In6.Cu")
		(net "M_C_CPU1_SA_CB<2>")
	)
	(segment
		(start 66.460624 -269.143988)
		(end 65.882774 -269.143988)
		(width 0.18288)
		(layer "In6.Cu")
		(net "M_C_CPU1_SA_CB<2>")
	)
	(segment
		(start 68.263262 -267.34135)
		(end 66.460624 -269.143988)
		(width 0.18288)
		(layer "In6.Cu")
		(net "M_C_CPU1_SA_CB<2>")
	)
	(segment
		(start 42.070782 -276.534626)
		(end 41.67759 -276.141434)
		(width 0.18288)
		(layer "In6.Cu")
		(net "M_C_CPU1_SA_CB<2>")
	)
	(segment
		(start 41.67759 -276.141434)
		(end 41.419018 -276.141434)
		(width 0.18288)
		(layer "In6.Cu")
		(net "M_C_CPU1_SA_CB<2>")
	)
	(arc
		(start 88.537796 -262.548116)
		(mid 88.255094 -262.623892)
		(end 87.972392 -262.548116)
		(width 0.088646)
		(layer "In6.Cu")
		(net "M_C_CPU1_SA_CB<2>")
	)
	(arc
		(start 89.851992 -262.548116)
		(mid 89.664794 -262.497973)
		(end 89.477596 -262.548116)
		(width 0.088646)
		(layer "In6.Cu")
		(net "M_C_CPU1_SA_CB<2>")
	)
	(arc
		(start 95.490792 -262.548116)
		(mid 95.303594 -262.497973)
		(end 95.116396 -262.548116)
		(width 0.088646)
		(layer "In6.Cu")
		(net "M_C_CPU1_SA_CB<2>")
	)
	(arc
		(start 86.658196 -262.548116)
		(mid 86.375494 -262.623892)
		(end 86.092792 -262.548116)
		(width 0.088646)
		(layer "In6.Cu")
		(net "M_C_CPU1_SA_CB<2>")
	)
	(arc
		(start 96.335088 -262.124444)
		(mid 96.2478 -262.3664)
		(end 96.062292 -262.54456)
		(width 0.088646)
		(layer "In6.Cu")
		(net "M_C_CPU1_SA_CB<2>")
	)
	(arc
		(start 96.041464 -262.556752)
		(mid 95.764989 -262.624072)
		(end 95.490792 -262.548116)
		(width 0.088646)
		(layer "In6.Cu")
		(net "M_C_CPU1_SA_CB<2>")
	)
	(arc
		(start 87.597996 -262.548116)
		(mid 87.315294 -262.623892)
		(end 87.032592 -262.548116)
		(width 0.088646)
		(layer "In6.Cu")
		(net "M_C_CPU1_SA_CB<2>")
	)
	(arc
		(start 85.718396 -262.548116)
		(mid 85.435694 -262.623892)
		(end 85.152992 -262.548116)
		(width 0.088646)
		(layer "In6.Cu")
		(net "M_C_CPU1_SA_CB<2>")
	)
	(arc
		(start 87.032592 -262.548116)
		(mid 86.845394 -262.497973)
		(end 86.658196 -262.548116)
		(width 0.088646)
		(layer "In6.Cu")
		(net "M_C_CPU1_SA_CB<2>")
	)
	(arc
		(start 91.731592 -262.548116)
		(mid 91.544394 -262.497973)
		(end 91.357196 -262.548116)
		(width 0.088646)
		(layer "In6.Cu")
		(net "M_C_CPU1_SA_CB<2>")
	)
	(arc
		(start 94.161864 -262.556752)
		(mid 93.885389 -262.624072)
		(end 93.611192 -262.548116)
		(width 0.088646)
		(layer "In6.Cu")
		(net "M_C_CPU1_SA_CB<2>")
	)
	(arc
		(start 90.792046 -262.548116)
		(mid 90.604848 -262.497973)
		(end 90.41765 -262.548116)
		(width 0.088646)
		(layer "In6.Cu")
		(net "M_C_CPU1_SA_CB<2>")
	)
	(arc
		(start 85.152992 -262.548116)
		(mid 84.965794 -262.497973)
		(end 84.778596 -262.548116)
		(width 0.088646)
		(layer "In6.Cu")
		(net "M_C_CPU1_SA_CB<2>")
	)
	(arc
		(start 90.41765 -262.548116)
		(mid 90.140837 -262.623986)
		(end 89.862406 -262.554212)
		(width 0.088646)
		(layer "In6.Cu")
		(net "M_C_CPU1_SA_CB<2>")
	)
	(arc
		(start 94.550992 -262.548116)
		(mid 94.363794 -262.497973)
		(end 94.176596 -262.548116)
		(width 0.088646)
		(layer "In6.Cu")
		(net "M_C_CPU1_SA_CB<2>")
	)
	(arc
		(start 91.357196 -262.548116)
		(mid 91.080637 -262.623859)
		(end 90.80246 -262.554212)
		(width 0.088646)
		(layer "In6.Cu")
		(net "M_C_CPU1_SA_CB<2>")
	)
	(arc
		(start 84.620608 -262.610346)
		(mid 84.472351 -262.666561)
		(end 84.345526 -262.76173)
		(width 0.088646)
		(layer "In6.Cu")
		(net "M_C_CPU1_SA_CB<2>")
	)
	(arc
		(start 93.611192 -262.548116)
		(mid 93.423994 -262.497973)
		(end 93.236796 -262.548116)
		(width 0.088646)
		(layer "In6.Cu")
		(net "M_C_CPU1_SA_CB<2>")
	)
	(arc
		(start 93.222064 -262.556752)
		(mid 92.945589 -262.624072)
		(end 92.671392 -262.548116)
		(width 0.088646)
		(layer "In6.Cu")
		(net "M_C_CPU1_SA_CB<2>")
	)
	(arc
		(start 84.778596 -262.548116)
		(mid 84.701947 -262.58518)
		(end 84.620608 -262.610346)
		(width 0.088646)
		(layer "In6.Cu")
		(net "M_C_CPU1_SA_CB<2>")
	)
	(arc
		(start 89.477596 -262.548116)
		(mid 89.194894 -262.623892)
		(end 88.912192 -262.548116)
		(width 0.088646)
		(layer "In6.Cu")
		(net "M_C_CPU1_SA_CB<2>")
	)
	(arc
		(start 87.972392 -262.548116)
		(mid 87.785194 -262.497973)
		(end 87.597996 -262.548116)
		(width 0.088646)
		(layer "In6.Cu")
		(net "M_C_CPU1_SA_CB<2>")
	)
	(arc
		(start 86.092792 -262.548116)
		(mid 85.905594 -262.497973)
		(end 85.718396 -262.548116)
		(width 0.088646)
		(layer "In6.Cu")
		(net "M_C_CPU1_SA_CB<2>")
	)
	(arc
		(start 88.912192 -262.548116)
		(mid 88.724994 -262.497973)
		(end 88.537796 -262.548116)
		(width 0.088646)
		(layer "In6.Cu")
		(net "M_C_CPU1_SA_CB<2>")
	)
	(arc
		(start 92.671392 -262.548116)
		(mid 92.484194 -262.497973)
		(end 92.296996 -262.548116)
		(width 0.088646)
		(layer "In6.Cu")
		(net "M_C_CPU1_SA_CB<2>")
	)
	(arc
		(start 92.282264 -262.556752)
		(mid 92.005789 -262.624072)
		(end 91.731592 -262.548116)
		(width 0.088646)
		(layer "In6.Cu")
		(net "M_C_CPU1_SA_CB<2>")
	)
	(arc
		(start 95.101664 -262.556752)
		(mid 94.825189 -262.624072)
		(end 94.550992 -262.548116)
		(width 0.088646)
		(layer "In6.Cu")
		(net "M_C_CPU1_SA_CB<2>")
	)
	(segment
		(start 25.432512 -277.273512)
		(end 25.432512 -276.954234)
		(width 0.20066)
		(layer "F.Cu")
		(net "M_C_CPU1_SA_CB<1>")
	)
	(segment
		(start 28.198318 -276.791674)
		(end 28.594812 -276.791674)
		(width 0.101854)
		(layer "F.Cu")
		(net "M_C_CPU1_SA_CB<1>")
	)
	(segment
		(start 23.228046 -277.216616)
		(end 24.562308 -277.216616)
		(width 0.20066)
		(layer "F.Cu")
		(net "M_C_CPU1_SA_CB<1>")
	)
	(segment
		(start 24.562308 -277.216616)
		(end 24.773636 -277.427944)
		(width 0.20066)
		(layer "F.Cu")
		(net "M_C_CPU1_SA_CB<1>")
	)
	(segment
		(start 95.303848 -261.244588)
		(end 95.303594 -261.244842)
		(width 0.20066)
		(layer "F.Cu")
		(net "M_C_CPU1_SA_CB<1>")
	)
	(segment
		(start 95.303848 -260.708902)
		(end 95.303848 -261.244588)
		(width 0.20066)
		(layer "F.Cu")
		(net "M_C_CPU1_SA_CB<1>")
	)
	(segment
		(start 28.707588 -276.791674)
		(end 29.13253 -277.216616)
		(width 0.20066)
		(layer "F.Cu")
		(net "M_C_CPU1_SA_CB<1>")
	)
	(segment
		(start 25.27808 -277.427944)
		(end 25.432512 -277.273512)
		(width 0.20066)
		(layer "F.Cu")
		(net "M_C_CPU1_SA_CB<1>")
	)
	(segment
		(start 25.432512 -276.954234)
		(end 25.595072 -276.791674)
		(width 0.20066)
		(layer "F.Cu")
		(net "M_C_CPU1_SA_CB<1>")
	)
	(segment
		(start 31.876746 -277.216616)
		(end 30.771846 -277.216616)
		(width 0.20066)
		(layer "F.Cu")
		(net "M_C_CPU1_SA_CB<1>")
	)
	(segment
		(start 26.2128 -276.791674)
		(end 28.198318 -276.791674)
		(width 0.1016)
		(layer "F.Cu")
		(net "M_C_CPU1_SA_CB<1>")
	)
	(segment
		(start 25.595072 -276.791674)
		(end 26.070052 -276.791674)
		(width 0.20066)
		(layer "F.Cu")
		(net "M_C_CPU1_SA_CB<1>")
	)
	(segment
		(start 29.13253 -277.216616)
		(end 30.771846 -277.216616)
		(width 0.20066)
		(layer "F.Cu")
		(net "M_C_CPU1_SA_CB<1>")
	)
	(segment
		(start 28.594812 -276.791674)
		(end 28.707588 -276.791674)
		(width 0.20066)
		(layer "F.Cu")
		(net "M_C_CPU1_SA_CB<1>")
	)
	(segment
		(start 26.070052 -276.791674)
		(end 26.2128 -276.791674)
		(width 0.101854)
		(layer "F.Cu")
		(net "M_C_CPU1_SA_CB<1>")
	)
	(segment
		(start 24.773636 -277.427944)
		(end 25.27808 -277.427944)
		(width 0.20066)
		(layer "F.Cu")
		(net "M_C_CPU1_SA_CB<1>")
	)
	(segment
		(start 47.731426 -271.6911)
		(end 45.284898 -271.6911)
		(width 0.18288)
		(layer "In6.Cu")
		(net "M_C_CPU1_SA_CB<1>")
	)
	(segment
		(start 32.156654 -276.936708)
		(end 31.876746 -277.216616)
		(width 0.18288)
		(layer "In6.Cu")
		(net "M_C_CPU1_SA_CB<1>")
	)
	(segment
		(start 92.296996 -261.5692)
		(end 92.282264 -261.560564)
		(width 0.088646)
		(layer "In6.Cu")
		(net "M_C_CPU1_SA_CB<1>")
	)
	(segment
		(start 94.176596 -261.5692)
		(end 94.161864 -261.560564)
		(width 0.088646)
		(layer "In6.Cu")
		(net "M_C_CPU1_SA_CB<1>")
	)
	(segment
		(start 32.509968 -276.79015)
		(end 32.156654 -276.936708)
		(width 0.18288)
		(layer "In6.Cu")
		(net "M_C_CPU1_SA_CB<1>")
	)
	(segment
		(start 83.798918 -261.619746)
		(end 83.02117 -262.397494)
		(width 0.088646)
		(layer "In6.Cu")
		(net "M_C_CPU1_SA_CB<1>")
	)
	(segment
		(start 45.284898 -271.6911)
		(end 45.073824 -271.480026)
		(width 0.18288)
		(layer "In6.Cu")
		(net "M_C_CPU1_SA_CB<1>")
	)
	(segment
		(start 40.345106 -273.557746)
		(end 39.527226 -274.375626)
		(width 0.18288)
		(layer "In6.Cu")
		(net "M_C_CPU1_SA_CB<1>")
	)
	(segment
		(start 55.909718 -268.289786)
		(end 55.059072 -269.140432)
		(width 0.18288)
		(layer "In6.Cu")
		(net "M_C_CPU1_SA_CB<1>")
	)
	(segment
		(start 33.247584 -276.286976)
		(end 33.094168 -275.917152)
		(width 0.18288)
		(layer "In6.Cu")
		(net "M_C_CPU1_SA_CB<1>")
	)
	(segment
		(start 65.61709 -266.878562)
		(end 64.146938 -268.348714)
		(width 0.18288)
		(layer "In6.Cu")
		(net "M_C_CPU1_SA_CB<1>")
	)
	(segment
		(start 43.108626 -271.861026)
		(end 41.411906 -273.557746)
		(width 0.18288)
		(layer "In6.Cu")
		(net "M_C_CPU1_SA_CB<1>")
	)
	(segment
		(start 63.464186 -268.348714)
		(end 62.816486 -267.701014)
		(width 0.18288)
		(layer "In6.Cu")
		(net "M_C_CPU1_SA_CB<1>")
	)
	(segment
		(start 84.025994 -261.619746)
		(end 83.798918 -261.619746)
		(width 0.088646)
		(layer "In6.Cu")
		(net "M_C_CPU1_SA_CB<1>")
	)
	(segment
		(start 32.554672 -275.942806)
		(end 32.455612 -276.181566)
		(width 0.18288)
		(layer "In6.Cu")
		(net "M_C_CPU1_SA_CB<1>")
	)
	(segment
		(start 88.912192 -261.568946)
		(end 88.90127 -261.575296)
		(width 0.088646)
		(layer "In6.Cu")
		(net "M_C_CPU1_SA_CB<1>")
	)
	(segment
		(start 35.07105 -276.036786)
		(end 34.329624 -276.036786)
		(width 0.18288)
		(layer "In6.Cu")
		(net "M_C_CPU1_SA_CB<1>")
	)
	(segment
		(start 37.821108 -275.091144)
		(end 35.496754 -275.091144)
		(width 0.18288)
		(layer "In6.Cu")
		(net "M_C_CPU1_SA_CB<1>")
	)
	(segment
		(start 93.236796 -261.5692)
		(end 93.222064 -261.560564)
		(width 0.088646)
		(layer "In6.Cu")
		(net "M_C_CPU1_SA_CB<1>")
	)
	(segment
		(start 55.059072 -269.140432)
		(end 50.282094 -269.140432)
		(width 0.18288)
		(layer "In6.Cu")
		(net "M_C_CPU1_SA_CB<1>")
	)
	(segment
		(start 61.688726 -267.701014)
		(end 61.099954 -268.289786)
		(width 0.18288)
		(layer "In6.Cu")
		(net "M_C_CPU1_SA_CB<1>")
	)
	(segment
		(start 61.099954 -268.289786)
		(end 55.909718 -268.289786)
		(width 0.18288)
		(layer "In6.Cu")
		(net "M_C_CPU1_SA_CB<1>")
	)
	(segment
		(start 34.329624 -276.036786)
		(end 33.486344 -276.386036)
		(width 0.18288)
		(layer "In6.Cu")
		(net "M_C_CPU1_SA_CB<1>")
	)
	(segment
		(start 41.411906 -273.557746)
		(end 40.345106 -273.557746)
		(width 0.18288)
		(layer "In6.Cu")
		(net "M_C_CPU1_SA_CB<1>")
	)
	(segment
		(start 83.02117 -262.397494)
		(end 82.658204 -262.397494)
		(width 0.088646)
		(layer "In6.Cu")
		(net "M_C_CPU1_SA_CB<1>")
	)
	(segment
		(start 44.454826 -271.480026)
		(end 44.073826 -271.861026)
		(width 0.18288)
		(layer "In6.Cu")
		(net "M_C_CPU1_SA_CB<1>")
	)
	(segment
		(start 35.19805 -275.389848)
		(end 35.19805 -275.909786)
		(width 0.18288)
		(layer "In6.Cu")
		(net "M_C_CPU1_SA_CB<1>")
	)
	(segment
		(start 81.572862 -262.397494)
		(end 78.41996 -263.703308)
		(width 0.18288)
		(layer "In6.Cu")
		(net "M_C_CPU1_SA_CB<1>")
	)
	(segment
		(start 89.477596 -261.568946)
		(end 89.462864 -261.56031)
		(width 0.088646)
		(layer "In6.Cu")
		(net "M_C_CPU1_SA_CB<1>")
	)
	(segment
		(start 82.658204 -262.397494)
		(end 81.572862 -262.397494)
		(width 0.18288)
		(layer "In6.Cu")
		(net "M_C_CPU1_SA_CB<1>")
	)
	(segment
		(start 38.536626 -274.375626)
		(end 37.821108 -275.091144)
		(width 0.18288)
		(layer "In6.Cu")
		(net "M_C_CPU1_SA_CB<1>")
	)
	(segment
		(start 33.486344 -276.386036)
		(end 33.247584 -276.286976)
		(width 0.18288)
		(layer "In6.Cu")
		(net "M_C_CPU1_SA_CB<1>")
	)
	(segment
		(start 32.855408 -275.818092)
		(end 32.554672 -275.942806)
		(width 0.18288)
		(layer "In6.Cu")
		(net "M_C_CPU1_SA_CB<1>")
	)
	(segment
		(start 66.293492 -266.878562)
		(end 65.61709 -266.878562)
		(width 0.18288)
		(layer "In6.Cu")
		(net "M_C_CPU1_SA_CB<1>")
	)
	(segment
		(start 67.199256 -265.972798)
		(end 66.293492 -266.878562)
		(width 0.18288)
		(layer "In6.Cu")
		(net "M_C_CPU1_SA_CB<1>")
	)
	(segment
		(start 32.609028 -276.55139)
		(end 32.509968 -276.79015)
		(width 0.18288)
		(layer "In6.Cu")
		(net "M_C_CPU1_SA_CB<1>")
	)
	(segment
		(start 50.282094 -269.140432)
		(end 47.731426 -271.6911)
		(width 0.18288)
		(layer "In6.Cu")
		(net "M_C_CPU1_SA_CB<1>")
	)
	(segment
		(start 35.496754 -275.091144)
		(end 35.19805 -275.389848)
		(width 0.18288)
		(layer "In6.Cu")
		(net "M_C_CPU1_SA_CB<1>")
	)
	(segment
		(start 64.146938 -268.348714)
		(end 63.464186 -268.348714)
		(width 0.18288)
		(layer "In6.Cu")
		(net "M_C_CPU1_SA_CB<1>")
	)
	(segment
		(start 33.094168 -275.917152)
		(end 32.855408 -275.818092)
		(width 0.18288)
		(layer "In6.Cu")
		(net "M_C_CPU1_SA_CB<1>")
	)
	(segment
		(start 39.527226 -274.375626)
		(end 38.536626 -274.375626)
		(width 0.18288)
		(layer "In6.Cu")
		(net "M_C_CPU1_SA_CB<1>")
	)
	(segment
		(start 35.19805 -275.909786)
		(end 35.07105 -276.036786)
		(width 0.18288)
		(layer "In6.Cu")
		(net "M_C_CPU1_SA_CB<1>")
	)
	(segment
		(start 89.488518 -261.575296)
		(end 89.477596 -261.568946)
		(width 0.088646)
		(layer "In6.Cu")
		(net "M_C_CPU1_SA_CB<1>")
	)
	(segment
		(start 78.41996 -263.703308)
		(end 72.678544 -263.703308)
		(width 0.18288)
		(layer "In6.Cu")
		(net "M_C_CPU1_SA_CB<1>")
	)
	(segment
		(start 45.073824 -271.480026)
		(end 44.454826 -271.480026)
		(width 0.18288)
		(layer "In6.Cu")
		(net "M_C_CPU1_SA_CB<1>")
	)
	(segment
		(start 72.678544 -263.703308)
		(end 67.199256 -265.972798)
		(width 0.18288)
		(layer "In6.Cu")
		(net "M_C_CPU1_SA_CB<1>")
	)
	(segment
		(start 44.073826 -271.861026)
		(end 43.108626 -271.861026)
		(width 0.18288)
		(layer "In6.Cu")
		(net "M_C_CPU1_SA_CB<1>")
	)
	(segment
		(start 32.455612 -276.181566)
		(end 32.609028 -276.55139)
		(width 0.18288)
		(layer "In6.Cu")
		(net "M_C_CPU1_SA_CB<1>")
	)
	(segment
		(start 62.816486 -267.701014)
		(end 61.688726 -267.701014)
		(width 0.18288)
		(layer "In6.Cu")
		(net "M_C_CPU1_SA_CB<1>")
	)
	(arc
		(start 93.222064 -261.560564)
		(mid 92.945589 -261.493244)
		(end 92.671392 -261.5692)
		(width 0.088646)
		(layer "In6.Cu")
		(net "M_C_CPU1_SA_CB<1>")
	)
	(arc
		(start 87.597996 -261.5692)
		(mid 87.315294 -261.493424)
		(end 87.032592 -261.5692)
		(width 0.088646)
		(layer "In6.Cu")
		(net "M_C_CPU1_SA_CB<1>")
	)
	(arc
		(start 87.032592 -261.5692)
		(mid 86.845394 -261.619343)
		(end 86.658196 -261.5692)
		(width 0.088646)
		(layer "In6.Cu")
		(net "M_C_CPU1_SA_CB<1>")
	)
	(arc
		(start 88.90127 -261.575296)
		(mid 88.71874 -261.61932)
		(end 88.537796 -261.5692)
		(width 0.088646)
		(layer "In6.Cu")
		(net "M_C_CPU1_SA_CB<1>")
	)
	(arc
		(start 84.778596 -261.5692)
		(mid 84.495894 -261.493424)
		(end 84.213192 -261.5692)
		(width 0.088646)
		(layer "In6.Cu")
		(net "M_C_CPU1_SA_CB<1>")
	)
	(arc
		(start 84.213192 -261.5692)
		(mid 84.12292 -261.606799)
		(end 84.025994 -261.619746)
		(width 0.088646)
		(layer "In6.Cu")
		(net "M_C_CPU1_SA_CB<1>")
	)
	(arc
		(start 93.611192 -261.5692)
		(mid 93.423994 -261.619343)
		(end 93.236796 -261.5692)
		(width 0.088646)
		(layer "In6.Cu")
		(net "M_C_CPU1_SA_CB<1>")
	)
	(arc
		(start 90.417396 -261.5692)
		(mid 90.134694 -261.493424)
		(end 89.851992 -261.5692)
		(width 0.088646)
		(layer "In6.Cu")
		(net "M_C_CPU1_SA_CB<1>")
	)
	(arc
		(start 94.161864 -261.560564)
		(mid 93.885389 -261.493244)
		(end 93.611192 -261.5692)
		(width 0.088646)
		(layer "In6.Cu")
		(net "M_C_CPU1_SA_CB<1>")
	)
	(arc
		(start 94.550992 -261.5692)
		(mid 94.363794 -261.619343)
		(end 94.176596 -261.5692)
		(width 0.088646)
		(layer "In6.Cu")
		(net "M_C_CPU1_SA_CB<1>")
	)
	(arc
		(start 89.462864 -261.56031)
		(mid 89.186389 -261.49299)
		(end 88.912192 -261.568946)
		(width 0.088646)
		(layer "In6.Cu")
		(net "M_C_CPU1_SA_CB<1>")
	)
	(arc
		(start 91.357196 -261.5692)
		(mid 91.074494 -261.493424)
		(end 90.791792 -261.5692)
		(width 0.088646)
		(layer "In6.Cu")
		(net "M_C_CPU1_SA_CB<1>")
	)
	(arc
		(start 85.152992 -261.5692)
		(mid 84.965794 -261.619343)
		(end 84.778596 -261.5692)
		(width 0.088646)
		(layer "In6.Cu")
		(net "M_C_CPU1_SA_CB<1>")
	)
	(arc
		(start 86.658196 -261.5692)
		(mid 86.375494 -261.493424)
		(end 86.092792 -261.5692)
		(width 0.088646)
		(layer "In6.Cu")
		(net "M_C_CPU1_SA_CB<1>")
	)
	(arc
		(start 87.972392 -261.5692)
		(mid 87.785194 -261.619343)
		(end 87.597996 -261.5692)
		(width 0.088646)
		(layer "In6.Cu")
		(net "M_C_CPU1_SA_CB<1>")
	)
	(arc
		(start 95.303594 -261.244842)
		(mid 94.917834 -261.385073)
		(end 94.550992 -261.5692)
		(width 0.088646)
		(layer "In6.Cu")
		(net "M_C_CPU1_SA_CB<1>")
	)
	(arc
		(start 90.791792 -261.5692)
		(mid 90.604594 -261.619343)
		(end 90.417396 -261.5692)
		(width 0.088646)
		(layer "In6.Cu")
		(net "M_C_CPU1_SA_CB<1>")
	)
	(arc
		(start 92.671392 -261.5692)
		(mid 92.484194 -261.619343)
		(end 92.296996 -261.5692)
		(width 0.088646)
		(layer "In6.Cu")
		(net "M_C_CPU1_SA_CB<1>")
	)
	(arc
		(start 89.851992 -261.5692)
		(mid 89.671048 -261.619291)
		(end 89.488518 -261.575296)
		(width 0.088646)
		(layer "In6.Cu")
		(net "M_C_CPU1_SA_CB<1>")
	)
	(arc
		(start 88.537796 -261.5692)
		(mid 88.255094 -261.493424)
		(end 87.972392 -261.5692)
		(width 0.088646)
		(layer "In6.Cu")
		(net "M_C_CPU1_SA_CB<1>")
	)
	(arc
		(start 86.092792 -261.5692)
		(mid 85.905594 -261.619343)
		(end 85.718396 -261.5692)
		(width 0.088646)
		(layer "In6.Cu")
		(net "M_C_CPU1_SA_CB<1>")
	)
	(arc
		(start 92.282264 -261.560564)
		(mid 92.005789 -261.493244)
		(end 91.731592 -261.5692)
		(width 0.088646)
		(layer "In6.Cu")
		(net "M_C_CPU1_SA_CB<1>")
	)
	(arc
		(start 85.718396 -261.5692)
		(mid 85.435694 -261.493424)
		(end 85.152992 -261.5692)
		(width 0.088646)
		(layer "In6.Cu")
		(net "M_C_CPU1_SA_CB<1>")
	)
	(arc
		(start 91.731592 -261.5692)
		(mid 91.544394 -261.619343)
		(end 91.357196 -261.5692)
		(width 0.088646)
		(layer "In6.Cu")
		(net "M_C_CPU1_SA_CB<1>")
	)
	(segment
		(start 28.977844 -278.491696)
		(end 29.402786 -278.916638)
		(width 0.20066)
		(layer "F.Cu")
		(net "M_C_CPU1_SA_CB<0>")
	)
	(segment
		(start 95.773494 -261.522718)
		(end 95.773494 -262.058404)
		(width 0.20066)
		(layer "F.Cu")
		(net "M_C_CPU1_SA_CB<0>")
	)
	(segment
		(start 26.069798 -278.491696)
		(end 26.459942 -278.491696)
		(width 0.101854)
		(layer "F.Cu")
		(net "M_C_CPU1_SA_CB<0>")
	)
	(segment
		(start 95.773494 -262.058404)
		(end 95.773748 -262.058658)
		(width 0.20066)
		(layer "F.Cu")
		(net "M_C_CPU1_SA_CB<0>")
	)
	(segment
		(start 31.876746 -278.916638)
		(end 30.771846 -278.916638)
		(width 0.20066)
		(layer "F.Cu")
		(net "M_C_CPU1_SA_CB<0>")
	)
	(segment
		(start 25.432512 -278.693118)
		(end 25.633934 -278.491696)
		(width 0.20066)
		(layer "F.Cu")
		(net "M_C_CPU1_SA_CB<0>")
	)
	(segment
		(start 25.432512 -278.982678)
		(end 25.432512 -278.693118)
		(width 0.20066)
		(layer "F.Cu")
		(net "M_C_CPU1_SA_CB<0>")
	)
	(segment
		(start 23.228046 -278.916638)
		(end 24.562308 -278.916638)
		(width 0.20066)
		(layer "F.Cu")
		(net "M_C_CPU1_SA_CB<0>")
	)
	(segment
		(start 29.402786 -278.916638)
		(end 30.771846 -278.916638)
		(width 0.20066)
		(layer "F.Cu")
		(net "M_C_CPU1_SA_CB<0>")
	)
	(segment
		(start 25.259792 -279.155398)
		(end 25.432512 -278.982678)
		(width 0.20066)
		(layer "F.Cu")
		(net "M_C_CPU1_SA_CB<0>")
	)
	(segment
		(start 26.459942 -278.491696)
		(end 28.529026 -278.491696)
		(width 0.1016)
		(layer "F.Cu")
		(net "M_C_CPU1_SA_CB<0>")
	)
	(segment
		(start 24.801068 -279.155398)
		(end 25.259792 -279.155398)
		(width 0.20066)
		(layer "F.Cu")
		(net "M_C_CPU1_SA_CB<0>")
	)
	(segment
		(start 28.529026 -278.491696)
		(end 28.594558 -278.491696)
		(width 0.101854)
		(layer "F.Cu")
		(net "M_C_CPU1_SA_CB<0>")
	)
	(segment
		(start 25.633934 -278.491696)
		(end 26.069798 -278.491696)
		(width 0.20066)
		(layer "F.Cu")
		(net "M_C_CPU1_SA_CB<0>")
	)
	(segment
		(start 28.594558 -278.491696)
		(end 28.977844 -278.491696)
		(width 0.20066)
		(layer "F.Cu")
		(net "M_C_CPU1_SA_CB<0>")
	)
	(segment
		(start 24.562308 -278.916638)
		(end 24.801068 -279.155398)
		(width 0.20066)
		(layer "F.Cu")
		(net "M_C_CPU1_SA_CB<0>")
	)
	(segment
		(start 83.402678 -263.406636)
		(end 82.658204 -263.406636)
		(width 0.088646)
		(layer "In6.Cu")
		(net "M_C_CPU1_SA_CB<0>")
	)
	(segment
		(start 65.927224 -268.292834)
		(end 64.171322 -270.048736)
		(width 0.18288)
		(layer "In6.Cu")
		(net "M_C_CPU1_SA_CB<0>")
	)
	(segment
		(start 37.888926 -276.788372)
		(end 34.926778 -276.788372)
		(width 0.18288)
		(layer "In6.Cu")
		(net "M_C_CPU1_SA_CB<0>")
	)
	(segment
		(start 82.658204 -263.406636)
		(end 81.738978 -263.406636)
		(width 0.18288)
		(layer "In6.Cu")
		(net "M_C_CPU1_SA_CB<0>")
	)
	(segment
		(start 92.216478 -262.37438)
		(end 92.201746 -262.383016)
		(width 0.088646)
		(layer "In6.Cu")
		(net "M_C_CPU1_SA_CB<0>")
	)
	(segment
		(start 88.452706 -262.37692)
		(end 88.442292 -262.383016)
		(width 0.088646)
		(layer "In6.Cu")
		(net "M_C_CPU1_SA_CB<0>")
	)
	(segment
		(start 34.926778 -276.788372)
		(end 32.798512 -278.916638)
		(width 0.18288)
		(layer "In6.Cu")
		(net "M_C_CPU1_SA_CB<0>")
	)
	(segment
		(start 67.617594 -267.030962)
		(end 66.355722 -268.292834)
		(width 0.18288)
		(layer "In6.Cu")
		(net "M_C_CPU1_SA_CB<0>")
	)
	(segment
		(start 91.272106 -262.37692)
		(end 91.261692 -262.383016)
		(width 0.088646)
		(layer "In6.Cu")
		(net "M_C_CPU1_SA_CB<0>")
	)
	(segment
		(start 50.728626 -270.840962)
		(end 49.72685 -271.842738)
		(width 0.18288)
		(layer "In6.Cu")
		(net "M_C_CPU1_SA_CB<0>")
	)
	(segment
		(start 43.208956 -273.391376)
		(end 41.77538 -274.824952)
		(width 0.18288)
		(layer "In6.Cu")
		(net "M_C_CPU1_SA_CB<0>")
	)
	(segment
		(start 39.868348 -275.771356)
		(end 38.905942 -275.771356)
		(width 0.18288)
		(layer "In6.Cu")
		(net "M_C_CPU1_SA_CB<0>")
	)
	(segment
		(start 61.76899 -269.144242)
		(end 60.038996 -270.874236)
		(width 0.18288)
		(layer "In6.Cu")
		(net "M_C_CPU1_SA_CB<0>")
	)
	(segment
		(start 62.655196 -269.144242)
		(end 61.76899 -269.144242)
		(width 0.18288)
		(layer "In6.Cu")
		(net "M_C_CPU1_SA_CB<0>")
	)
	(segment
		(start 90.887296 -262.383016)
		(end 90.872564 -262.37438)
		(width 0.088646)
		(layer "In6.Cu")
		(net "M_C_CPU1_SA_CB<0>")
	)
	(segment
		(start 64.171322 -270.048736)
		(end 63.55969 -270.048736)
		(width 0.18288)
		(layer "In6.Cu")
		(net "M_C_CPU1_SA_CB<0>")
	)
	(segment
		(start 38.905942 -275.771356)
		(end 37.888926 -276.788372)
		(width 0.18288)
		(layer "In6.Cu")
		(net "M_C_CPU1_SA_CB<0>")
	)
	(segment
		(start 60.038996 -270.874236)
		(end 59.631326 -270.874236)
		(width 0.18288)
		(layer "In6.Cu")
		(net "M_C_CPU1_SA_CB<0>")
	)
	(segment
		(start 41.77538 -274.824952)
		(end 40.814752 -274.824952)
		(width 0.18288)
		(layer "In6.Cu")
		(net "M_C_CPU1_SA_CB<0>")
	)
	(segment
		(start 66.355722 -268.292834)
		(end 65.927224 -268.292834)
		(width 0.18288)
		(layer "In6.Cu")
		(net "M_C_CPU1_SA_CB<0>")
	)
	(segment
		(start 63.55969 -270.048736)
		(end 62.655196 -269.144242)
		(width 0.18288)
		(layer "In6.Cu")
		(net "M_C_CPU1_SA_CB<0>")
	)
	(segment
		(start 40.814752 -274.824952)
		(end 39.868348 -275.771356)
		(width 0.18288)
		(layer "In6.Cu")
		(net "M_C_CPU1_SA_CB<0>")
	)
	(segment
		(start 81.738978 -263.406636)
		(end 78.568042 -264.72007)
		(width 0.18288)
		(layer "In6.Cu")
		(net "M_C_CPU1_SA_CB<0>")
	)
	(segment
		(start 95.035878 -262.37438)
		(end 95.021146 -262.383016)
		(width 0.088646)
		(layer "In6.Cu")
		(net "M_C_CPU1_SA_CB<0>")
	)
	(segment
		(start 59.059826 -270.302736)
		(end 55.517034 -270.302736)
		(width 0.18288)
		(layer "In6.Cu")
		(net "M_C_CPU1_SA_CB<0>")
	)
	(segment
		(start 32.798512 -278.916638)
		(end 31.876746 -278.916638)
		(width 0.18288)
		(layer "In6.Cu")
		(net "M_C_CPU1_SA_CB<0>")
	)
	(segment
		(start 95.969836 -262.377936)
		(end 95.960946 -262.383016)
		(width 0.088646)
		(layer "In6.Cu")
		(net "M_C_CPU1_SA_CB<0>")
	)
	(segment
		(start 49.72685 -271.842738)
		(end 49.72685 -272.83537)
		(width 0.18288)
		(layer "In6.Cu")
		(net "M_C_CPU1_SA_CB<0>")
	)
	(segment
		(start 49.72685 -272.83537)
		(end 49.170844 -273.391376)
		(width 0.18288)
		(layer "In6.Cu")
		(net "M_C_CPU1_SA_CB<0>")
	)
	(segment
		(start 94.096078 -262.37438)
		(end 94.081346 -262.383016)
		(width 0.088646)
		(layer "In6.Cu")
		(net "M_C_CPU1_SA_CB<0>")
	)
	(segment
		(start 84.267294 -262.54202)
		(end 83.402678 -263.406636)
		(width 0.088646)
		(layer "In6.Cu")
		(net "M_C_CPU1_SA_CB<0>")
	)
	(segment
		(start 55.517034 -270.302736)
		(end 54.978808 -270.840962)
		(width 0.18288)
		(layer "In6.Cu")
		(net "M_C_CPU1_SA_CB<0>")
	)
	(segment
		(start 95.773748 -262.058658)
		(end 96.086422 -262.058658)
		(width 0.088646)
		(layer "In6.Cu")
		(net "M_C_CPU1_SA_CB<0>")
	)
	(segment
		(start 73.197974 -264.72007)
		(end 67.617594 -267.030962)
		(width 0.18288)
		(layer "In6.Cu")
		(net "M_C_CPU1_SA_CB<0>")
	)
	(segment
		(start 78.568042 -264.72007)
		(end 73.197974 -264.72007)
		(width 0.18288)
		(layer "In6.Cu")
		(net "M_C_CPU1_SA_CB<0>")
	)
	(segment
		(start 49.170844 -273.391376)
		(end 43.208956 -273.391376)
		(width 0.18288)
		(layer "In6.Cu")
		(net "M_C_CPU1_SA_CB<0>")
	)
	(segment
		(start 59.631326 -270.874236)
		(end 59.059826 -270.302736)
		(width 0.18288)
		(layer "In6.Cu")
		(net "M_C_CPU1_SA_CB<0>")
	)
	(segment
		(start 89.007696 -262.383016)
		(end 89.00795 -262.383016)
		(width 0.088646)
		(layer "In6.Cu")
		(net "M_C_CPU1_SA_CB<0>")
	)
	(segment
		(start 96.086422 -262.058658)
		(end 96.143826 -262.116062)
		(width 0.088646)
		(layer "In6.Cu")
		(net "M_C_CPU1_SA_CB<0>")
	)
	(segment
		(start 93.156278 -262.37438)
		(end 93.141546 -262.383016)
		(width 0.088646)
		(layer "In6.Cu")
		(net "M_C_CPU1_SA_CB<0>")
	)
	(segment
		(start 54.978808 -270.840962)
		(end 50.728626 -270.840962)
		(width 0.18288)
		(layer "In6.Cu")
		(net "M_C_CPU1_SA_CB<0>")
	)
	(arc
		(start 93.70695 -262.383016)
		(mid 93.432751 -262.307181)
		(end 93.156278 -262.37438)
		(width 0.088646)
		(layer "In6.Cu")
		(net "M_C_CPU1_SA_CB<0>")
	)
	(arc
		(start 88.067896 -262.383016)
		(mid 87.785194 -262.30724)
		(end 87.502492 -262.383016)
		(width 0.088646)
		(layer "In6.Cu")
		(net "M_C_CPU1_SA_CB<0>")
	)
	(arc
		(start 94.64675 -262.383016)
		(mid 94.372551 -262.307181)
		(end 94.096078 -262.37438)
		(width 0.088646)
		(layer "In6.Cu")
		(net "M_C_CPU1_SA_CB<0>")
	)
	(arc
		(start 88.442292 -262.383016)
		(mid 88.255094 -262.433159)
		(end 88.067896 -262.383016)
		(width 0.088646)
		(layer "In6.Cu")
		(net "M_C_CPU1_SA_CB<0>")
	)
	(arc
		(start 89.947496 -262.383016)
		(mid 89.664794 -262.30724)
		(end 89.382092 -262.383016)
		(width 0.088646)
		(layer "In6.Cu")
		(net "M_C_CPU1_SA_CB<0>")
	)
	(arc
		(start 96.143826 -262.116062)
		(mid 96.08567 -262.266175)
		(end 95.969836 -262.377936)
		(width 0.088646)
		(layer "In6.Cu")
		(net "M_C_CPU1_SA_CB<0>")
	)
	(arc
		(start 89.00795 -262.383016)
		(mid 88.731137 -262.307146)
		(end 88.452706 -262.37692)
		(width 0.088646)
		(layer "In6.Cu")
		(net "M_C_CPU1_SA_CB<0>")
	)
	(arc
		(start 91.82735 -262.383016)
		(mid 91.550537 -262.307146)
		(end 91.272106 -262.37692)
		(width 0.088646)
		(layer "In6.Cu")
		(net "M_C_CPU1_SA_CB<0>")
	)
	(arc
		(start 95.021146 -262.383016)
		(mid 94.833948 -262.433159)
		(end 94.64675 -262.383016)
		(width 0.088646)
		(layer "In6.Cu")
		(net "M_C_CPU1_SA_CB<0>")
	)
	(arc
		(start 85.248496 -262.383016)
		(mid 84.965794 -262.30724)
		(end 84.683092 -262.383016)
		(width 0.088646)
		(layer "In6.Cu")
		(net "M_C_CPU1_SA_CB<0>")
	)
	(arc
		(start 85.622892 -262.383016)
		(mid 85.435694 -262.433159)
		(end 85.248496 -262.383016)
		(width 0.088646)
		(layer "In6.Cu")
		(net "M_C_CPU1_SA_CB<0>")
	)
	(arc
		(start 94.081346 -262.383016)
		(mid 93.894148 -262.433159)
		(end 93.70695 -262.383016)
		(width 0.088646)
		(layer "In6.Cu")
		(net "M_C_CPU1_SA_CB<0>")
	)
	(arc
		(start 95.960946 -262.383016)
		(mid 95.773748 -262.433159)
		(end 95.58655 -262.383016)
		(width 0.088646)
		(layer "In6.Cu")
		(net "M_C_CPU1_SA_CB<0>")
	)
	(arc
		(start 92.201746 -262.383016)
		(mid 92.014548 -262.433159)
		(end 91.82735 -262.383016)
		(width 0.088646)
		(layer "In6.Cu")
		(net "M_C_CPU1_SA_CB<0>")
	)
	(arc
		(start 93.141546 -262.383016)
		(mid 92.954348 -262.433159)
		(end 92.76715 -262.383016)
		(width 0.088646)
		(layer "In6.Cu")
		(net "M_C_CPU1_SA_CB<0>")
	)
	(arc
		(start 90.872564 -262.37438)
		(mid 90.596089 -262.30706)
		(end 90.321892 -262.383016)
		(width 0.088646)
		(layer "In6.Cu")
		(net "M_C_CPU1_SA_CB<0>")
	)
	(arc
		(start 95.58655 -262.383016)
		(mid 95.312351 -262.307181)
		(end 95.035878 -262.37438)
		(width 0.088646)
		(layer "In6.Cu")
		(net "M_C_CPU1_SA_CB<0>")
	)
	(arc
		(start 86.188296 -262.383016)
		(mid 85.905594 -262.30724)
		(end 85.622892 -262.383016)
		(width 0.088646)
		(layer "In6.Cu")
		(net "M_C_CPU1_SA_CB<0>")
	)
	(arc
		(start 89.382092 -262.383016)
		(mid 89.194894 -262.433159)
		(end 89.007696 -262.383016)
		(width 0.088646)
		(layer "In6.Cu")
		(net "M_C_CPU1_SA_CB<0>")
	)
	(arc
		(start 84.683092 -262.383016)
		(mid 84.601606 -262.417987)
		(end 84.514182 -262.4328)
		(width 0.088646)
		(layer "In6.Cu")
		(net "M_C_CPU1_SA_CB<0>")
	)
	(arc
		(start 90.321892 -262.383016)
		(mid 90.134694 -262.433159)
		(end 89.947496 -262.383016)
		(width 0.088646)
		(layer "In6.Cu")
		(net "M_C_CPU1_SA_CB<0>")
	)
	(arc
		(start 87.502492 -262.383016)
		(mid 87.315294 -262.433159)
		(end 87.128096 -262.383016)
		(width 0.088646)
		(layer "In6.Cu")
		(net "M_C_CPU1_SA_CB<0>")
	)
	(arc
		(start 87.128096 -262.383016)
		(mid 86.845394 -262.30724)
		(end 86.562692 -262.383016)
		(width 0.088646)
		(layer "In6.Cu")
		(net "M_C_CPU1_SA_CB<0>")
	)
	(arc
		(start 86.562692 -262.383016)
		(mid 86.375494 -262.433159)
		(end 86.188296 -262.383016)
		(width 0.088646)
		(layer "In6.Cu")
		(net "M_C_CPU1_SA_CB<0>")
	)
	(arc
		(start 92.76715 -262.383016)
		(mid 92.492951 -262.307181)
		(end 92.216478 -262.37438)
		(width 0.088646)
		(layer "In6.Cu")
		(net "M_C_CPU1_SA_CB<0>")
	)
	(arc
		(start 84.514182 -262.4328)
		(mid 84.380529 -262.464354)
		(end 84.267294 -262.54202)
		(width 0.088646)
		(layer "In6.Cu")
		(net "M_C_CPU1_SA_CB<0>")
	)
	(arc
		(start 91.261692 -262.383016)
		(mid 91.074494 -262.433159)
		(end 90.887296 -262.383016)
		(width 0.088646)
		(layer "In6.Cu")
		(net "M_C_CPU1_SA_CB<0>")
	)
	(segment
		(start 28.707588 -260.641846)
		(end 29.13253 -261.066788)
		(width 0.20066)
		(layer "F.Cu")
		(net "M_C_CPU1_SA_CA<6>")
	)
	(segment
		(start 29.13253 -261.066788)
		(end 30.771846 -261.066788)
		(width 0.20066)
		(layer "F.Cu")
		(net "M_C_CPU1_SA_CA<6>")
	)
	(segment
		(start 25.27808 -261.278116)
		(end 25.432512 -261.123684)
		(width 0.20066)
		(layer "F.Cu")
		(net "M_C_CPU1_SA_CA<6>")
	)
	(segment
		(start 25.432512 -261.123684)
		(end 25.432512 -260.795516)
		(width 0.20066)
		(layer "F.Cu")
		(net "M_C_CPU1_SA_CA<6>")
	)
	(segment
		(start 26.20391 -260.632956)
		(end 26.2128 -260.641846)
		(width 0.1016)
		(layer "F.Cu")
		(net "M_C_CPU1_SA_CA<6>")
	)
	(segment
		(start 25.432512 -260.795516)
		(end 25.595072 -260.632956)
		(width 0.20066)
		(layer "F.Cu")
		(net "M_C_CPU1_SA_CA<6>")
	)
	(segment
		(start 24.562308 -261.066788)
		(end 24.773636 -261.278116)
		(width 0.20066)
		(layer "F.Cu")
		(net "M_C_CPU1_SA_CA<6>")
	)
	(segment
		(start 28.198318 -260.641846)
		(end 28.529026 -260.641846)
		(width 0.101854)
		(layer "F.Cu")
		(net "M_C_CPU1_SA_CA<6>")
	)
	(segment
		(start 23.228046 -261.066788)
		(end 24.562308 -261.066788)
		(width 0.20066)
		(layer "F.Cu")
		(net "M_C_CPU1_SA_CA<6>")
	)
	(segment
		(start 28.529026 -260.641846)
		(end 28.707588 -260.641846)
		(width 0.20066)
		(layer "F.Cu")
		(net "M_C_CPU1_SA_CA<6>")
	)
	(segment
		(start 31.876746 -261.066788)
		(end 30.771846 -261.066788)
		(width 0.20066)
		(layer "F.Cu")
		(net "M_C_CPU1_SA_CA<6>")
	)
	(segment
		(start 26.2128 -260.641846)
		(end 28.198318 -260.641846)
		(width 0.1016)
		(layer "F.Cu")
		(net "M_C_CPU1_SA_CA<6>")
	)
	(segment
		(start 25.595072 -260.632956)
		(end 26.20391 -260.632956)
		(width 0.20066)
		(layer "F.Cu")
		(net "M_C_CPU1_SA_CA<6>")
	)
	(segment
		(start 24.773636 -261.278116)
		(end 25.27808 -261.278116)
		(width 0.20066)
		(layer "F.Cu")
		(net "M_C_CPU1_SA_CA<6>")
	)
	(segment
		(start 92.484448 -254.733298)
		(end 92.484194 -254.733552)
		(width 0.20066)
		(layer "F.Cu")
		(net "M_C_CPU1_SA_CA<6>")
	)
	(segment
		(start 92.484448 -254.197612)
		(end 92.484448 -254.733298)
		(width 0.20066)
		(layer "F.Cu")
		(net "M_C_CPU1_SA_CA<6>")
	)
	(segment
		(start 55.951628 -258.941824)
		(end 55.61203 -258.602226)
		(width 0.18288)
		(layer "In4.Cu")
		(net "M_C_CPU1_SA_CA<6>")
	)
	(segment
		(start 82.701384 -253.52121)
		(end 80.386174 -255.83642)
		(width 0.18288)
		(layer "In4.Cu")
		(net "M_C_CPU1_SA_CA<6>")
	)
	(segment
		(start 41.888664 -259.649976)
		(end 39.353236 -259.649976)
		(width 0.18288)
		(layer "In4.Cu")
		(net "M_C_CPU1_SA_CA<6>")
	)
	(segment
		(start 84.434934 -253.52121)
		(end 82.701384 -253.52121)
		(width 0.18288)
		(layer "In4.Cu")
		(net "M_C_CPU1_SA_CA<6>")
	)
	(segment
		(start 90.806778 -254.41783)
		(end 90.806524 -254.417576)
		(width 0.088646)
		(layer "In4.Cu")
		(net "M_C_CPU1_SA_CA<6>")
	)
	(segment
		(start 36.161218 -261.49173)
		(end 32.301688 -261.49173)
		(width 0.18288)
		(layer "In4.Cu")
		(net "M_C_CPU1_SA_CA<6>")
	)
	(segment
		(start 36.478972 -261.173976)
		(end 36.161218 -261.49173)
		(width 0.18288)
		(layer "In4.Cu")
		(net "M_C_CPU1_SA_CA<6>")
	)
	(segment
		(start 42.880534 -260.641846)
		(end 41.888664 -259.649976)
		(width 0.18288)
		(layer "In4.Cu")
		(net "M_C_CPU1_SA_CA<6>")
	)
	(segment
		(start 55.260748 -258.602226)
		(end 54.92115 -258.941824)
		(width 0.18288)
		(layer "In4.Cu")
		(net "M_C_CPU1_SA_CA<6>")
	)
	(segment
		(start 44.21378 -260.070854)
		(end 44.21378 -260.194552)
		(width 0.18288)
		(layer "In4.Cu")
		(net "M_C_CPU1_SA_CA<6>")
	)
	(segment
		(start 65.926208 -257.966972)
		(end 65.925954 -257.967226)
		(width 0.18288)
		(layer "In4.Cu")
		(net "M_C_CPU1_SA_CA<6>")
	)
	(segment
		(start 85.975698 -254.319532)
		(end 85.177376 -253.52121)
		(width 0.088646)
		(layer "In4.Cu")
		(net "M_C_CPU1_SA_CA<6>")
	)
	(segment
		(start 44.21378 -260.194552)
		(end 43.766486 -260.641846)
		(width 0.18288)
		(layer "In4.Cu")
		(net "M_C_CPU1_SA_CA<6>")
	)
	(segment
		(start 32.301688 -261.49173)
		(end 31.876746 -261.066788)
		(width 0.18288)
		(layer "In4.Cu")
		(net "M_C_CPU1_SA_CA<6>")
	)
	(segment
		(start 80.386174 -255.83642)
		(end 72.312022 -255.83642)
		(width 0.18288)
		(layer "In4.Cu")
		(net "M_C_CPU1_SA_CA<6>")
	)
	(segment
		(start 72.312022 -255.83642)
		(end 67.168268 -257.966972)
		(width 0.18288)
		(layer "In4.Cu")
		(net "M_C_CPU1_SA_CA<6>")
	)
	(segment
		(start 67.168268 -257.966972)
		(end 65.926208 -257.966972)
		(width 0.18288)
		(layer "In4.Cu")
		(net "M_C_CPU1_SA_CA<6>")
	)
	(segment
		(start 54.92115 -258.941824)
		(end 50.084228 -258.941824)
		(width 0.18288)
		(layer "In4.Cu")
		(net "M_C_CPU1_SA_CA<6>")
	)
	(segment
		(start 90.806524 -254.417576)
		(end 90.791792 -254.409194)
		(width 0.088646)
		(layer "In4.Cu")
		(net "M_C_CPU1_SA_CA<6>")
	)
	(segment
		(start 58.43651 -257.967226)
		(end 57.461912 -258.941824)
		(width 0.18288)
		(layer "In4.Cu")
		(net "M_C_CPU1_SA_CA<6>")
	)
	(segment
		(start 39.353236 -259.649976)
		(end 37.829236 -261.173976)
		(width 0.18288)
		(layer "In4.Cu")
		(net "M_C_CPU1_SA_CA<6>")
	)
	(segment
		(start 43.766486 -260.641846)
		(end 42.880534 -260.641846)
		(width 0.18288)
		(layer "In4.Cu")
		(net "M_C_CPU1_SA_CA<6>")
	)
	(segment
		(start 50.084228 -258.941824)
		(end 49.234344 -259.791708)
		(width 0.18288)
		(layer "In4.Cu")
		(net "M_C_CPU1_SA_CA<6>")
	)
	(segment
		(start 57.461912 -258.941824)
		(end 55.951628 -258.941824)
		(width 0.18288)
		(layer "In4.Cu")
		(net "M_C_CPU1_SA_CA<6>")
	)
	(segment
		(start 65.925954 -257.967226)
		(end 58.43651 -257.967226)
		(width 0.18288)
		(layer "In4.Cu")
		(net "M_C_CPU1_SA_CA<6>")
	)
	(segment
		(start 37.829236 -261.173976)
		(end 36.478972 -261.173976)
		(width 0.18288)
		(layer "In4.Cu")
		(net "M_C_CPU1_SA_CA<6>")
	)
	(segment
		(start 55.61203 -258.602226)
		(end 55.260748 -258.602226)
		(width 0.18288)
		(layer "In4.Cu")
		(net "M_C_CPU1_SA_CA<6>")
	)
	(segment
		(start 49.234344 -259.791708)
		(end 44.492926 -259.791708)
		(width 0.18288)
		(layer "In4.Cu")
		(net "M_C_CPU1_SA_CA<6>")
	)
	(segment
		(start 92.113354 -254.632968)
		(end 91.731846 -254.409194)
		(width 0.088646)
		(layer "In4.Cu")
		(net "M_C_CPU1_SA_CA<6>")
	)
	(segment
		(start 44.492926 -259.791708)
		(end 44.21378 -260.070854)
		(width 0.18288)
		(layer "In4.Cu")
		(net "M_C_CPU1_SA_CA<6>")
	)
	(segment
		(start 85.177376 -253.52121)
		(end 84.434934 -253.52121)
		(width 0.088646)
		(layer "In4.Cu")
		(net "M_C_CPU1_SA_CA<6>")
	)
	(arc
		(start 90.417396 -254.409194)
		(mid 90.134694 -254.48497)
		(end 89.851992 -254.409194)
		(width 0.088646)
		(layer "In4.Cu")
		(net "M_C_CPU1_SA_CA<6>")
	)
	(arc
		(start 91.731846 -254.409194)
		(mid 91.544648 -254.359051)
		(end 91.35745 -254.409194)
		(width 0.088646)
		(layer "In4.Cu")
		(net "M_C_CPU1_SA_CA<6>")
	)
	(arc
		(start 88.912192 -254.409194)
		(mid 88.724994 -254.359051)
		(end 88.537796 -254.409194)
		(width 0.088646)
		(layer "In4.Cu")
		(net "M_C_CPU1_SA_CA<6>")
	)
	(arc
		(start 88.537796 -254.409194)
		(mid 88.255094 -254.48497)
		(end 87.972392 -254.409194)
		(width 0.088646)
		(layer "In4.Cu")
		(net "M_C_CPU1_SA_CA<6>")
	)
	(arc
		(start 92.484194 -254.733552)
		(mid 92.292064 -254.707995)
		(end 92.113354 -254.632968)
		(width 0.088646)
		(layer "In4.Cu")
		(net "M_C_CPU1_SA_CA<6>")
	)
	(arc
		(start 90.791792 -254.409194)
		(mid 90.604594 -254.359051)
		(end 90.417396 -254.409194)
		(width 0.088646)
		(layer "In4.Cu")
		(net "M_C_CPU1_SA_CA<6>")
	)
	(arc
		(start 86.658196 -254.409194)
		(mid 86.375494 -254.48497)
		(end 86.092792 -254.409194)
		(width 0.088646)
		(layer "In4.Cu")
		(net "M_C_CPU1_SA_CA<6>")
	)
	(arc
		(start 87.972392 -254.409194)
		(mid 87.785194 -254.359051)
		(end 87.597996 -254.409194)
		(width 0.088646)
		(layer "In4.Cu")
		(net "M_C_CPU1_SA_CA<6>")
	)
	(arc
		(start 87.597996 -254.409194)
		(mid 87.315294 -254.48497)
		(end 87.032592 -254.409194)
		(width 0.088646)
		(layer "In4.Cu")
		(net "M_C_CPU1_SA_CA<6>")
	)
	(arc
		(start 89.477596 -254.409194)
		(mid 89.194894 -254.48497)
		(end 88.912192 -254.409194)
		(width 0.088646)
		(layer "In4.Cu")
		(net "M_C_CPU1_SA_CA<6>")
	)
	(arc
		(start 86.092792 -254.409194)
		(mid 86.031314 -254.368192)
		(end 85.975698 -254.319532)
		(width 0.088646)
		(layer "In4.Cu")
		(net "M_C_CPU1_SA_CA<6>")
	)
	(arc
		(start 87.032592 -254.409194)
		(mid 86.845394 -254.359051)
		(end 86.658196 -254.409194)
		(width 0.088646)
		(layer "In4.Cu")
		(net "M_C_CPU1_SA_CA<6>")
	)
	(arc
		(start 91.35745 -254.409194)
		(mid 91.083251 -254.485029)
		(end 90.806778 -254.41783)
		(width 0.088646)
		(layer "In4.Cu")
		(net "M_C_CPU1_SA_CA<6>")
	)
	(arc
		(start 89.851992 -254.409194)
		(mid 89.664794 -254.359051)
		(end 89.477596 -254.409194)
		(width 0.088646)
		(layer "In4.Cu")
		(net "M_C_CPU1_SA_CA<6>")
	)
	(segment
		(start 32.666178 -262.192516)
		(end 32.666178 -262.040878)
		(width 0.20066)
		(layer "F.Cu")
		(net "M_C_CPU1_SA_CA<5>")
	)
	(segment
		(start 93.424248 -255.825498)
		(end 93.424248 -256.361184)
		(width 0.20066)
		(layer "F.Cu")
		(net "M_C_CPU1_SA_CA<5>")
	)
	(segment
		(start 34.055812 -261.916672)
		(end 34.871914 -261.916672)
		(width 0.20066)
		(layer "F.Cu")
		(net "M_C_CPU1_SA_CA<5>")
	)
	(segment
		(start 27.328114 -261.916672)
		(end 29.025342 -261.916672)
		(width 0.20066)
		(layer "F.Cu")
		(net "M_C_CPU1_SA_CA<5>")
	)
	(segment
		(start 29.647642 -262.355838)
		(end 29.661866 -262.341614)
		(width 0.101854)
		(layer "F.Cu")
		(net "M_C_CPU1_SA_CA<5>")
	)
	(segment
		(start 35.976814 -261.916672)
		(end 34.871914 -261.916672)
		(width 0.20066)
		(layer "F.Cu")
		(net "M_C_CPU1_SA_CA<5>")
	)
	(segment
		(start 32.794702 -261.912354)
		(end 33.189926 -261.912354)
		(width 0.20066)
		(layer "F.Cu")
		(net "M_C_CPU1_SA_CA<5>")
	)
	(segment
		(start 93.424248 -256.361184)
		(end 93.423994 -256.361438)
		(width 0.20066)
		(layer "F.Cu")
		(net "M_C_CPU1_SA_CA<5>")
	)
	(segment
		(start 29.29382 -262.355838)
		(end 29.647642 -262.355838)
		(width 0.20066)
		(layer "F.Cu")
		(net "M_C_CPU1_SA_CA<5>")
	)
	(segment
		(start 32.666178 -262.040878)
		(end 32.794702 -261.912354)
		(width 0.20066)
		(layer "F.Cu")
		(net "M_C_CPU1_SA_CA<5>")
	)
	(segment
		(start 29.661866 -262.341614)
		(end 29.899864 -262.341614)
		(width 0.101854)
		(layer "F.Cu")
		(net "M_C_CPU1_SA_CA<5>")
	)
	(segment
		(start 29.151326 -262.042656)
		(end 29.151326 -262.213344)
		(width 0.20066)
		(layer "F.Cu")
		(net "M_C_CPU1_SA_CA<5>")
	)
	(segment
		(start 29.899864 -262.341614)
		(end 31.972758 -262.341614)
		(width 0.1016)
		(layer "F.Cu")
		(net "M_C_CPU1_SA_CA<5>")
	)
	(segment
		(start 33.401762 -262.12419)
		(end 33.848294 -262.12419)
		(width 0.20066)
		(layer "F.Cu")
		(net "M_C_CPU1_SA_CA<5>")
	)
	(segment
		(start 29.025342 -261.916672)
		(end 29.151326 -262.042656)
		(width 0.20066)
		(layer "F.Cu")
		(net "M_C_CPU1_SA_CA<5>")
	)
	(segment
		(start 31.972758 -262.341614)
		(end 32.51708 -262.341614)
		(width 0.20066)
		(layer "F.Cu")
		(net "M_C_CPU1_SA_CA<5>")
	)
	(segment
		(start 29.151326 -262.213344)
		(end 29.29382 -262.355838)
		(width 0.20066)
		(layer "F.Cu")
		(net "M_C_CPU1_SA_CA<5>")
	)
	(segment
		(start 33.848294 -262.12419)
		(end 34.055812 -261.916672)
		(width 0.20066)
		(layer "F.Cu")
		(net "M_C_CPU1_SA_CA<5>")
	)
	(segment
		(start 33.189926 -261.912354)
		(end 33.401762 -262.12419)
		(width 0.20066)
		(layer "F.Cu")
		(net "M_C_CPU1_SA_CA<5>")
	)
	(segment
		(start 32.51708 -262.341614)
		(end 32.666178 -262.192516)
		(width 0.20066)
		(layer "F.Cu")
		(net "M_C_CPU1_SA_CA<5>")
	)
	(segment
		(start 60.445396 -259.396992)
		(end 60.262516 -259.579872)
		(width 0.18288)
		(layer "In4.Cu")
		(net "M_C_CPU1_SA_CA<5>")
	)
	(segment
		(start 40.04564 -260.368796)
		(end 39.718234 -260.696202)
		(width 0.18288)
		(layer "In4.Cu")
		(net "M_C_CPU1_SA_CA<5>")
	)
	(segment
		(start 93.11132 -256.361438)
		(end 93.045788 -256.295906)
		(width 0.088646)
		(layer "In4.Cu")
		(net "M_C_CPU1_SA_CA<5>")
	)
	(segment
		(start 60.628276 -258.551426)
		(end 60.445396 -258.734306)
		(width 0.18288)
		(layer "In4.Cu")
		(net "M_C_CPU1_SA_CA<5>")
	)
	(segment
		(start 61.319156 -259.579872)
		(end 61.136276 -259.396992)
		(width 0.18288)
		(layer "In4.Cu")
		(net "M_C_CPU1_SA_CA<5>")
	)
	(segment
		(start 53.108606 -260.641846)
		(end 44.66971 -260.641846)
		(width 0.18288)
		(layer "In4.Cu")
		(net "M_C_CPU1_SA_CA<5>")
	)
	(segment
		(start 80.755236 -256.1717)
		(end 73.029064 -256.1717)
		(width 0.18288)
		(layer "In4.Cu")
		(net "M_C_CPU1_SA_CA<5>")
	)
	(segment
		(start 91.35745 -255.05791)
		(end 91.347036 -255.051814)
		(width 0.088646)
		(layer "In4.Cu")
		(net "M_C_CPU1_SA_CA<5>")
	)
	(segment
		(start 93.423994 -256.361438)
		(end 93.11132 -256.361438)
		(width 0.088646)
		(layer "In4.Cu")
		(net "M_C_CPU1_SA_CA<5>")
	)
	(segment
		(start 61.136276 -258.734306)
		(end 60.953396 -258.551426)
		(width 0.18288)
		(layer "In4.Cu")
		(net "M_C_CPU1_SA_CA<5>")
	)
	(segment
		(start 85.640418 -254.998728)
		(end 84.66074 -254.01905)
		(width 0.088646)
		(layer "In4.Cu")
		(net "M_C_CPU1_SA_CA<5>")
	)
	(segment
		(start 60.953396 -258.551426)
		(end 60.628276 -258.551426)
		(width 0.18288)
		(layer "In4.Cu")
		(net "M_C_CPU1_SA_CA<5>")
	)
	(segment
		(start 43.762676 -261.54888)
		(end 42.498264 -261.54888)
		(width 0.18288)
		(layer "In4.Cu")
		(net "M_C_CPU1_SA_CA<5>")
	)
	(segment
		(start 82.907886 -254.01905)
		(end 80.755236 -256.1717)
		(width 0.18288)
		(layer "In4.Cu")
		(net "M_C_CPU1_SA_CA<5>")
	)
	(segment
		(start 60.445396 -258.734306)
		(end 60.445396 -259.396992)
		(width 0.18288)
		(layer "In4.Cu")
		(net "M_C_CPU1_SA_CA<5>")
	)
	(segment
		(start 89.477596 -255.05791)
		(end 89.462864 -255.049274)
		(width 0.088646)
		(layer "In4.Cu")
		(net "M_C_CPU1_SA_CA<5>")
	)
	(segment
		(start 36.81222 -262.338312)
		(end 36.39058 -261.916672)
		(width 0.18288)
		(layer "In4.Cu")
		(net "M_C_CPU1_SA_CA<5>")
	)
	(segment
		(start 54.17058 -259.579872)
		(end 53.108606 -260.641846)
		(width 0.18288)
		(layer "In4.Cu")
		(net "M_C_CPU1_SA_CA<5>")
	)
	(segment
		(start 61.136276 -259.396992)
		(end 61.136276 -258.734306)
		(width 0.18288)
		(layer "In4.Cu")
		(net "M_C_CPU1_SA_CA<5>")
	)
	(segment
		(start 44.66971 -260.641846)
		(end 43.762676 -261.54888)
		(width 0.18288)
		(layer "In4.Cu")
		(net "M_C_CPU1_SA_CA<5>")
	)
	(segment
		(start 92.579698 -255.547622)
		(end 92.579698 -255.540002)
		(width 0.088646)
		(layer "In4.Cu")
		(net "M_C_CPU1_SA_CA<5>")
	)
	(segment
		(start 92.76715 -255.87198)
		(end 92.75826 -255.8669)
		(width 0.088646)
		(layer "In4.Cu")
		(net "M_C_CPU1_SA_CA<5>")
	)
	(segment
		(start 39.09568 -260.696202)
		(end 37.45357 -262.338312)
		(width 0.18288)
		(layer "In4.Cu")
		(net "M_C_CPU1_SA_CA<5>")
	)
	(segment
		(start 63.243968 -259.008626)
		(end 62.672722 -259.579872)
		(width 0.18288)
		(layer "In4.Cu")
		(net "M_C_CPU1_SA_CA<5>")
	)
	(segment
		(start 62.672722 -259.579872)
		(end 61.319156 -259.579872)
		(width 0.18288)
		(layer "In4.Cu")
		(net "M_C_CPU1_SA_CA<5>")
	)
	(segment
		(start 37.45357 -262.338312)
		(end 36.81222 -262.338312)
		(width 0.18288)
		(layer "In4.Cu")
		(net "M_C_CPU1_SA_CA<5>")
	)
	(segment
		(start 39.718234 -260.696202)
		(end 39.09568 -260.696202)
		(width 0.18288)
		(layer "In4.Cu")
		(net "M_C_CPU1_SA_CA<5>")
	)
	(segment
		(start 42.498264 -261.54888)
		(end 41.31818 -260.368796)
		(width 0.18288)
		(layer "In4.Cu")
		(net "M_C_CPU1_SA_CA<5>")
	)
	(segment
		(start 41.31818 -260.368796)
		(end 40.04564 -260.368796)
		(width 0.18288)
		(layer "In4.Cu")
		(net "M_C_CPU1_SA_CA<5>")
	)
	(segment
		(start 84.434934 -254.01905)
		(end 82.907886 -254.01905)
		(width 0.18288)
		(layer "In4.Cu")
		(net "M_C_CPU1_SA_CA<5>")
	)
	(segment
		(start 36.39058 -261.916672)
		(end 35.976814 -261.916672)
		(width 0.18288)
		(layer "In4.Cu")
		(net "M_C_CPU1_SA_CA<5>")
	)
	(segment
		(start 73.029064 -256.1717)
		(end 66.180208 -259.008626)
		(width 0.18288)
		(layer "In4.Cu")
		(net "M_C_CPU1_SA_CA<5>")
	)
	(segment
		(start 60.262516 -259.579872)
		(end 54.17058 -259.579872)
		(width 0.18288)
		(layer "In4.Cu")
		(net "M_C_CPU1_SA_CA<5>")
	)
	(segment
		(start 84.66074 -254.01905)
		(end 84.434934 -254.01905)
		(width 0.088646)
		(layer "In4.Cu")
		(net "M_C_CPU1_SA_CA<5>")
	)
	(segment
		(start 91.74226 -255.051814)
		(end 91.731846 -255.05791)
		(width 0.088646)
		(layer "In4.Cu")
		(net "M_C_CPU1_SA_CA<5>")
	)
	(segment
		(start 66.180208 -259.008626)
		(end 63.243968 -259.008626)
		(width 0.18288)
		(layer "In4.Cu")
		(net "M_C_CPU1_SA_CA<5>")
	)
	(arc
		(start 92.579698 -255.540002)
		(mid 92.502069 -255.261589)
		(end 92.296996 -255.05791)
		(width 0.088646)
		(layer "In4.Cu")
		(net "M_C_CPU1_SA_CA<5>")
	)
	(arc
		(start 89.462864 -255.049274)
		(mid 89.186423 -254.982108)
		(end 88.912192 -255.05791)
		(width 0.088646)
		(layer "In4.Cu")
		(net "M_C_CPU1_SA_CA<5>")
	)
	(arc
		(start 93.045788 -256.295906)
		(mid 92.9567 -256.050921)
		(end 92.76715 -255.87198)
		(width 0.088646)
		(layer "In4.Cu")
		(net "M_C_CPU1_SA_CA<5>")
	)
	(arc
		(start 87.032592 -255.05791)
		(mid 86.845394 -255.108053)
		(end 86.658196 -255.05791)
		(width 0.088646)
		(layer "In4.Cu")
		(net "M_C_CPU1_SA_CA<5>")
	)
	(arc
		(start 90.417396 -255.05791)
		(mid 90.134694 -254.982168)
		(end 89.851992 -255.05791)
		(width 0.088646)
		(layer "In4.Cu")
		(net "M_C_CPU1_SA_CA<5>")
	)
	(arc
		(start 85.718396 -255.05791)
		(mid 85.677466 -255.030877)
		(end 85.640418 -254.998728)
		(width 0.088646)
		(layer "In4.Cu")
		(net "M_C_CPU1_SA_CA<5>")
	)
	(arc
		(start 89.851992 -255.05791)
		(mid 89.664794 -255.108053)
		(end 89.477596 -255.05791)
		(width 0.088646)
		(layer "In4.Cu")
		(net "M_C_CPU1_SA_CA<5>")
	)
	(arc
		(start 90.791792 -255.05791)
		(mid 90.604594 -255.108053)
		(end 90.417396 -255.05791)
		(width 0.088646)
		(layer "In4.Cu")
		(net "M_C_CPU1_SA_CA<5>")
	)
	(arc
		(start 92.75826 -255.8669)
		(mid 92.627346 -255.73054)
		(end 92.579698 -255.547622)
		(width 0.088646)
		(layer "In4.Cu")
		(net "M_C_CPU1_SA_CA<5>")
	)
	(arc
		(start 86.658196 -255.05791)
		(mid 86.375494 -254.982168)
		(end 86.092792 -255.05791)
		(width 0.088646)
		(layer "In4.Cu")
		(net "M_C_CPU1_SA_CA<5>")
	)
	(arc
		(start 88.912192 -255.05791)
		(mid 88.724994 -255.108053)
		(end 88.537796 -255.05791)
		(width 0.088646)
		(layer "In4.Cu")
		(net "M_C_CPU1_SA_CA<5>")
	)
	(arc
		(start 86.092792 -255.05791)
		(mid 85.905594 -255.108053)
		(end 85.718396 -255.05791)
		(width 0.088646)
		(layer "In4.Cu")
		(net "M_C_CPU1_SA_CA<5>")
	)
	(arc
		(start 91.731846 -255.05791)
		(mid 91.544648 -255.108053)
		(end 91.35745 -255.05791)
		(width 0.088646)
		(layer "In4.Cu")
		(net "M_C_CPU1_SA_CA<5>")
	)
	(arc
		(start 87.597996 -255.05791)
		(mid 87.315294 -254.982168)
		(end 87.032592 -255.05791)
		(width 0.088646)
		(layer "In4.Cu")
		(net "M_C_CPU1_SA_CA<5>")
	)
	(arc
		(start 91.347036 -255.051814)
		(mid 91.068604 -254.982)
		(end 90.791792 -255.05791)
		(width 0.088646)
		(layer "In4.Cu")
		(net "M_C_CPU1_SA_CA<5>")
	)
	(arc
		(start 92.296996 -255.05791)
		(mid 92.020437 -254.982201)
		(end 91.74226 -255.051814)
		(width 0.088646)
		(layer "In4.Cu")
		(net "M_C_CPU1_SA_CA<5>")
	)
	(arc
		(start 88.537796 -255.05791)
		(mid 88.255094 -254.982168)
		(end 87.972392 -255.05791)
		(width 0.088646)
		(layer "In4.Cu")
		(net "M_C_CPU1_SA_CA<5>")
	)
	(arc
		(start 87.972392 -255.05791)
		(mid 87.785194 -255.108053)
		(end 87.597996 -255.05791)
		(width 0.088646)
		(layer "In4.Cu")
		(net "M_C_CPU1_SA_CA<5>")
	)
	(segment
		(start 24.562308 -262.76681)
		(end 24.773636 -262.978138)
		(width 0.20066)
		(layer "F.Cu")
		(net "M_C_CPU1_SA_CA<4>")
	)
	(segment
		(start 28.198318 -262.341868)
		(end 28.529026 -262.341868)
		(width 0.101854)
		(layer "F.Cu")
		(net "M_C_CPU1_SA_CA<4>")
	)
	(segment
		(start 25.595072 -262.332978)
		(end 26.20391 -262.332978)
		(width 0.20066)
		(layer "F.Cu")
		(net "M_C_CPU1_SA_CA<4>")
	)
	(segment
		(start 28.529026 -262.341868)
		(end 28.707588 -262.341868)
		(width 0.20066)
		(layer "F.Cu")
		(net "M_C_CPU1_SA_CA<4>")
	)
	(segment
		(start 23.228046 -262.76681)
		(end 24.562308 -262.76681)
		(width 0.20066)
		(layer "F.Cu")
		(net "M_C_CPU1_SA_CA<4>")
	)
	(segment
		(start 25.432512 -262.823706)
		(end 25.432512 -262.495538)
		(width 0.20066)
		(layer "F.Cu")
		(net "M_C_CPU1_SA_CA<4>")
	)
	(segment
		(start 29.13253 -262.76681)
		(end 30.771846 -262.76681)
		(width 0.20066)
		(layer "F.Cu")
		(net "M_C_CPU1_SA_CA<4>")
	)
	(segment
		(start 25.27808 -262.978138)
		(end 25.432512 -262.823706)
		(width 0.20066)
		(layer "F.Cu")
		(net "M_C_CPU1_SA_CA<4>")
	)
	(segment
		(start 92.484448 -255.825498)
		(end 92.484448 -256.361184)
		(width 0.20066)
		(layer "F.Cu")
		(net "M_C_CPU1_SA_CA<4>")
	)
	(segment
		(start 26.20391 -262.332978)
		(end 26.2128 -262.341868)
		(width 0.1016)
		(layer "F.Cu")
		(net "M_C_CPU1_SA_CA<4>")
	)
	(segment
		(start 25.432512 -262.495538)
		(end 25.595072 -262.332978)
		(width 0.20066)
		(layer "F.Cu")
		(net "M_C_CPU1_SA_CA<4>")
	)
	(segment
		(start 92.484448 -256.361184)
		(end 92.484194 -256.361438)
		(width 0.20066)
		(layer "F.Cu")
		(net "M_C_CPU1_SA_CA<4>")
	)
	(segment
		(start 28.707588 -262.341868)
		(end 29.13253 -262.76681)
		(width 0.20066)
		(layer "F.Cu")
		(net "M_C_CPU1_SA_CA<4>")
	)
	(segment
		(start 31.876746 -262.76681)
		(end 30.771846 -262.76681)
		(width 0.20066)
		(layer "F.Cu")
		(net "M_C_CPU1_SA_CA<4>")
	)
	(segment
		(start 26.2128 -262.341868)
		(end 28.198318 -262.341868)
		(width 0.1016)
		(layer "F.Cu")
		(net "M_C_CPU1_SA_CA<4>")
	)
	(segment
		(start 24.773636 -262.978138)
		(end 25.27808 -262.978138)
		(width 0.20066)
		(layer "F.Cu")
		(net "M_C_CPU1_SA_CA<4>")
	)
	(segment
		(start 92.796868 -256.361438)
		(end 92.854272 -256.304034)
		(width 0.088646)
		(layer "In4.Cu")
		(net "M_C_CPU1_SA_CA<4>")
	)
	(segment
		(start 55.715154 -260.123178)
		(end 54.346602 -261.49173)
		(width 0.18288)
		(layer "In4.Cu")
		(net "M_C_CPU1_SA_CA<4>")
	)
	(segment
		(start 89.39276 -255.22936)
		(end 89.382346 -255.223264)
		(width 0.088646)
		(layer "In4.Cu")
		(net "M_C_CPU1_SA_CA<4>")
	)
	(segment
		(start 92.210382 -255.228344)
		(end 92.201492 -255.223264)
		(width 0.088646)
		(layer "In4.Cu")
		(net "M_C_CPU1_SA_CA<4>")
	)
	(segment
		(start 37.8079 -263.19226)
		(end 35.6743 -263.19226)
		(width 0.18288)
		(layer "In4.Cu")
		(net "M_C_CPU1_SA_CA<4>")
	)
	(segment
		(start 39.77005 -261.295896)
		(end 39.228014 -261.295896)
		(width 0.18288)
		(layer "In4.Cu")
		(net "M_C_CPU1_SA_CA<4>")
	)
	(segment
		(start 38.533832 -261.990078)
		(end 38.533832 -262.466328)
		(width 0.18288)
		(layer "In4.Cu")
		(net "M_C_CPU1_SA_CA<4>")
	)
	(segment
		(start 92.671392 -256.03708)
		(end 92.665296 -256.033524)
		(width 0.088646)
		(layer "In4.Cu")
		(net "M_C_CPU1_SA_CA<4>")
	)
	(segment
		(start 32.301688 -262.341868)
		(end 31.876746 -262.76681)
		(width 0.18288)
		(layer "In4.Cu")
		(net "M_C_CPU1_SA_CA<4>")
	)
	(segment
		(start 90.332306 -255.22936)
		(end 90.321892 -255.223264)
		(width 0.088646)
		(layer "In4.Cu")
		(net "M_C_CPU1_SA_CA<4>")
	)
	(segment
		(start 58.78703 -260.123178)
		(end 55.715154 -260.123178)
		(width 0.18288)
		(layer "In4.Cu")
		(net "M_C_CPU1_SA_CA<4>")
	)
	(segment
		(start 35.6743 -263.19226)
		(end 34.823908 -262.341868)
		(width 0.18288)
		(layer "In4.Cu")
		(net "M_C_CPU1_SA_CA<4>")
	)
	(segment
		(start 92.680282 -256.04216)
		(end 92.671392 -256.03708)
		(width 0.088646)
		(layer "In4.Cu")
		(net "M_C_CPU1_SA_CA<4>")
	)
	(segment
		(start 62.352936 -260.707378)
		(end 59.37123 -260.707378)
		(width 0.18288)
		(layer "In4.Cu")
		(net "M_C_CPU1_SA_CA<4>")
	)
	(segment
		(start 59.37123 -260.707378)
		(end 58.78703 -260.123178)
		(width 0.18288)
		(layer "In4.Cu")
		(net "M_C_CPU1_SA_CA<4>")
	)
	(segment
		(start 91.827096 -255.223264)
		(end 91.816682 -255.22936)
		(width 0.088646)
		(layer "In4.Cu")
		(net "M_C_CPU1_SA_CA<4>")
	)
	(segment
		(start 44.562522 -261.49173)
		(end 43.946826 -262.107426)
		(width 0.18288)
		(layer "In4.Cu")
		(net "M_C_CPU1_SA_CA<4>")
	)
	(segment
		(start 85.505798 -255.133348)
		(end 84.88934 -254.51689)
		(width 0.088646)
		(layer "In4.Cu")
		(net "M_C_CPU1_SA_CA<4>")
	)
	(segment
		(start 43.946826 -262.107426)
		(end 40.58158 -262.107426)
		(width 0.18288)
		(layer "In4.Cu")
		(net "M_C_CPU1_SA_CA<4>")
	)
	(segment
		(start 83.114388 -254.51689)
		(end 81.124298 -256.50698)
		(width 0.18288)
		(layer "In4.Cu")
		(net "M_C_CPU1_SA_CA<4>")
	)
	(segment
		(start 63.543688 -259.516626)
		(end 62.352936 -260.707378)
		(width 0.18288)
		(layer "In4.Cu")
		(net "M_C_CPU1_SA_CA<4>")
	)
	(segment
		(start 40.58158 -262.107426)
		(end 39.77005 -261.295896)
		(width 0.18288)
		(layer "In4.Cu")
		(net "M_C_CPU1_SA_CA<4>")
	)
	(segment
		(start 66.286888 -259.516626)
		(end 63.543688 -259.516626)
		(width 0.18288)
		(layer "In4.Cu")
		(net "M_C_CPU1_SA_CA<4>")
	)
	(segment
		(start 88.452706 -255.22936)
		(end 88.442292 -255.223264)
		(width 0.088646)
		(layer "In4.Cu")
		(net "M_C_CPU1_SA_CA<4>")
	)
	(segment
		(start 73.553066 -256.50698)
		(end 66.286888 -259.516626)
		(width 0.18288)
		(layer "In4.Cu")
		(net "M_C_CPU1_SA_CA<4>")
	)
	(segment
		(start 92.484194 -256.361438)
		(end 92.796868 -256.361438)
		(width 0.088646)
		(layer "In4.Cu")
		(net "M_C_CPU1_SA_CA<4>")
	)
	(segment
		(start 54.346602 -261.49173)
		(end 44.562522 -261.49173)
		(width 0.18288)
		(layer "In4.Cu")
		(net "M_C_CPU1_SA_CA<4>")
	)
	(segment
		(start 34.823908 -262.341868)
		(end 32.301688 -262.341868)
		(width 0.18288)
		(layer "In4.Cu")
		(net "M_C_CPU1_SA_CA<4>")
	)
	(segment
		(start 84.434934 -254.51689)
		(end 83.114388 -254.51689)
		(width 0.18288)
		(layer "In4.Cu")
		(net "M_C_CPU1_SA_CA<4>")
	)
	(segment
		(start 84.88934 -254.51689)
		(end 84.434934 -254.51689)
		(width 0.088646)
		(layer "In4.Cu")
		(net "M_C_CPU1_SA_CA<4>")
	)
	(segment
		(start 38.533832 -262.466328)
		(end 37.8079 -263.19226)
		(width 0.18288)
		(layer "In4.Cu")
		(net "M_C_CPU1_SA_CA<4>")
	)
	(segment
		(start 81.124298 -256.50698)
		(end 73.553066 -256.50698)
		(width 0.18288)
		(layer "In4.Cu")
		(net "M_C_CPU1_SA_CA<4>")
	)
	(segment
		(start 39.228014 -261.295896)
		(end 38.533832 -261.990078)
		(width 0.18288)
		(layer "In4.Cu")
		(net "M_C_CPU1_SA_CA<4>")
	)
	(arc
		(start 91.261946 -255.223264)
		(mid 91.074748 -255.173121)
		(end 90.88755 -255.223264)
		(width 0.088646)
		(layer "In4.Cu")
		(net "M_C_CPU1_SA_CA<4>")
	)
	(arc
		(start 89.382346 -255.223264)
		(mid 89.195148 -255.173121)
		(end 89.00795 -255.223264)
		(width 0.088646)
		(layer "In4.Cu")
		(net "M_C_CPU1_SA_CA<4>")
	)
	(arc
		(start 86.562692 -255.223264)
		(mid 86.375494 -255.173121)
		(end 86.188296 -255.223264)
		(width 0.088646)
		(layer "In4.Cu")
		(net "M_C_CPU1_SA_CA<4>")
	)
	(arc
		(start 92.388944 -255.547622)
		(mid 92.341265 -255.364722)
		(end 92.210382 -255.228344)
		(width 0.088646)
		(layer "In4.Cu")
		(net "M_C_CPU1_SA_CA<4>")
	)
	(arc
		(start 89.947496 -255.223264)
		(mid 89.670937 -255.298973)
		(end 89.39276 -255.22936)
		(width 0.088646)
		(layer "In4.Cu")
		(net "M_C_CPU1_SA_CA<4>")
	)
	(arc
		(start 86.188296 -255.223264)
		(mid 85.831773 -255.294167)
		(end 85.505798 -255.133348)
		(width 0.088646)
		(layer "In4.Cu")
		(net "M_C_CPU1_SA_CA<4>")
	)
	(arc
		(start 87.502492 -255.223264)
		(mid 87.315294 -255.173121)
		(end 87.128096 -255.223264)
		(width 0.088646)
		(layer "In4.Cu")
		(net "M_C_CPU1_SA_CA<4>")
	)
	(arc
		(start 92.665296 -256.033524)
		(mid 92.462883 -255.827111)
		(end 92.388944 -255.547622)
		(width 0.088646)
		(layer "In4.Cu")
		(net "M_C_CPU1_SA_CA<4>")
	)
	(arc
		(start 88.067896 -255.223264)
		(mid 87.785194 -255.299006)
		(end 87.502492 -255.223264)
		(width 0.088646)
		(layer "In4.Cu")
		(net "M_C_CPU1_SA_CA<4>")
	)
	(arc
		(start 92.201492 -255.223264)
		(mid 92.014294 -255.173121)
		(end 91.827096 -255.223264)
		(width 0.088646)
		(layer "In4.Cu")
		(net "M_C_CPU1_SA_CA<4>")
	)
	(arc
		(start 87.128096 -255.223264)
		(mid 86.845394 -255.299006)
		(end 86.562692 -255.223264)
		(width 0.088646)
		(layer "In4.Cu")
		(net "M_C_CPU1_SA_CA<4>")
	)
	(arc
		(start 90.88755 -255.223264)
		(mid 90.610737 -255.2991)
		(end 90.332306 -255.22936)
		(width 0.088646)
		(layer "In4.Cu")
		(net "M_C_CPU1_SA_CA<4>")
	)
	(arc
		(start 90.321892 -255.223264)
		(mid 90.134694 -255.173121)
		(end 89.947496 -255.223264)
		(width 0.088646)
		(layer "In4.Cu")
		(net "M_C_CPU1_SA_CA<4>")
	)
	(arc
		(start 91.816682 -255.22936)
		(mid 91.538504 -255.299052)
		(end 91.261946 -255.223264)
		(width 0.088646)
		(layer "In4.Cu")
		(net "M_C_CPU1_SA_CA<4>")
	)
	(arc
		(start 88.442292 -255.223264)
		(mid 88.255094 -255.173121)
		(end 88.067896 -255.223264)
		(width 0.088646)
		(layer "In4.Cu")
		(net "M_C_CPU1_SA_CA<4>")
	)
	(arc
		(start 89.00795 -255.223264)
		(mid 88.731137 -255.2991)
		(end 88.452706 -255.22936)
		(width 0.088646)
		(layer "In4.Cu")
		(net "M_C_CPU1_SA_CA<4>")
	)
	(arc
		(start 92.854272 -256.304034)
		(mid 92.796116 -256.153921)
		(end 92.680282 -256.04216)
		(width 0.088646)
		(layer "In4.Cu")
		(net "M_C_CPU1_SA_CA<4>")
	)
	(segment
		(start 29.025342 -263.616694)
		(end 29.151326 -263.742678)
		(width 0.20066)
		(layer "F.Cu")
		(net "M_C_CPU1_SA_CA<3>")
	)
	(segment
		(start 29.661866 -264.041636)
		(end 29.899864 -264.041636)
		(width 0.101854)
		(layer "F.Cu")
		(net "M_C_CPU1_SA_CA<3>")
	)
	(segment
		(start 27.328114 -263.616694)
		(end 29.025342 -263.616694)
		(width 0.20066)
		(layer "F.Cu")
		(net "M_C_CPU1_SA_CA<3>")
	)
	(segment
		(start 34.055812 -263.616694)
		(end 34.871914 -263.616694)
		(width 0.20066)
		(layer "F.Cu")
		(net "M_C_CPU1_SA_CA<3>")
	)
	(segment
		(start 33.189926 -263.612376)
		(end 33.401762 -263.824212)
		(width 0.20066)
		(layer "F.Cu")
		(net "M_C_CPU1_SA_CA<3>")
	)
	(segment
		(start 32.666178 -263.892538)
		(end 32.666178 -263.7409)
		(width 0.20066)
		(layer "F.Cu")
		(net "M_C_CPU1_SA_CA<3>")
	)
	(segment
		(start 32.794702 -263.612376)
		(end 33.189926 -263.612376)
		(width 0.20066)
		(layer "F.Cu")
		(net "M_C_CPU1_SA_CA<3>")
	)
	(segment
		(start 33.848294 -263.824212)
		(end 34.055812 -263.616694)
		(width 0.20066)
		(layer "F.Cu")
		(net "M_C_CPU1_SA_CA<3>")
	)
	(segment
		(start 29.151326 -263.742678)
		(end 29.151326 -263.913366)
		(width 0.20066)
		(layer "F.Cu")
		(net "M_C_CPU1_SA_CA<3>")
	)
	(segment
		(start 29.29382 -264.05586)
		(end 29.647642 -264.05586)
		(width 0.20066)
		(layer "F.Cu")
		(net "M_C_CPU1_SA_CA<3>")
	)
	(segment
		(start 31.972758 -264.041636)
		(end 32.51708 -264.041636)
		(width 0.20066)
		(layer "F.Cu")
		(net "M_C_CPU1_SA_CA<3>")
	)
	(segment
		(start 33.401762 -263.824212)
		(end 33.848294 -263.824212)
		(width 0.20066)
		(layer "F.Cu")
		(net "M_C_CPU1_SA_CA<3>")
	)
	(segment
		(start 93.893894 -256.639314)
		(end 93.893894 -257.175)
		(width 0.20066)
		(layer "F.Cu")
		(net "M_C_CPU1_SA_CA<3>")
	)
	(segment
		(start 29.151326 -263.913366)
		(end 29.29382 -264.05586)
		(width 0.20066)
		(layer "F.Cu")
		(net "M_C_CPU1_SA_CA<3>")
	)
	(segment
		(start 35.976814 -263.616694)
		(end 34.871914 -263.616694)
		(width 0.20066)
		(layer "F.Cu")
		(net "M_C_CPU1_SA_CA<3>")
	)
	(segment
		(start 29.647642 -264.05586)
		(end 29.661866 -264.041636)
		(width 0.101854)
		(layer "F.Cu")
		(net "M_C_CPU1_SA_CA<3>")
	)
	(segment
		(start 32.51708 -264.041636)
		(end 32.666178 -263.892538)
		(width 0.20066)
		(layer "F.Cu")
		(net "M_C_CPU1_SA_CA<3>")
	)
	(segment
		(start 93.893894 -257.175)
		(end 93.894148 -257.175254)
		(width 0.20066)
		(layer "F.Cu")
		(net "M_C_CPU1_SA_CA<3>")
	)
	(segment
		(start 29.899864 -264.041636)
		(end 31.972758 -264.041636)
		(width 0.1016)
		(layer "F.Cu")
		(net "M_C_CPU1_SA_CA<3>")
	)
	(segment
		(start 32.666178 -263.7409)
		(end 32.794702 -263.612376)
		(width 0.20066)
		(layer "F.Cu")
		(net "M_C_CPU1_SA_CA<3>")
	)
	(segment
		(start 89.39276 -255.865884)
		(end 89.382346 -255.87198)
		(width 0.088646)
		(layer "In4.Cu")
		(net "M_C_CPU1_SA_CA<3>")
	)
	(segment
		(start 85.248496 -255.87198)
		(end 85.248242 -255.871726)
		(width 0.088646)
		(layer "In4.Cu")
		(net "M_C_CPU1_SA_CA<3>")
	)
	(segment
		(start 58.17235 -260.777482)
		(end 58.030618 -260.63575)
		(width 0.18288)
		(layer "In4.Cu")
		(net "M_C_CPU1_SA_CA<3>")
	)
	(segment
		(start 40.027352 -263.425432)
		(end 39.554658 -262.952738)
		(width 0.18288)
		(layer "In4.Cu")
		(net "M_C_CPU1_SA_CA<3>")
	)
	(segment
		(start 83.29041 -255.04521)
		(end 81.49336 -256.84226)
		(width 0.18288)
		(layer "In4.Cu")
		(net "M_C_CPU1_SA_CA<3>")
	)
	(segment
		(start 91.27236 -255.865884)
		(end 91.261946 -255.87198)
		(width 0.088646)
		(layer "In4.Cu")
		(net "M_C_CPU1_SA_CA<3>")
	)
	(segment
		(start 55.104792 -262.341868)
		(end 50.063146 -262.341868)
		(width 0.18288)
		(layer "In4.Cu")
		(net "M_C_CPU1_SA_CA<3>")
	)
	(segment
		(start 39.554658 -262.952738)
		(end 38.955726 -262.952738)
		(width 0.18288)
		(layer "In4.Cu")
		(net "M_C_CPU1_SA_CA<3>")
	)
	(segment
		(start 55.49138 -261.95528)
		(end 55.104792 -262.341868)
		(width 0.18288)
		(layer "In4.Cu")
		(net "M_C_CPU1_SA_CA<3>")
	)
	(segment
		(start 58.030618 -260.63575)
		(end 55.933086 -260.63575)
		(width 0.18288)
		(layer "In4.Cu")
		(net "M_C_CPU1_SA_CA<3>")
	)
	(segment
		(start 55.49138 -261.077456)
		(end 55.49138 -261.95528)
		(width 0.18288)
		(layer "In4.Cu")
		(net "M_C_CPU1_SA_CA<3>")
	)
	(segment
		(start 92.303092 -256.689352)
		(end 92.296996 -256.685796)
		(width 0.088646)
		(layer "In4.Cu")
		(net "M_C_CPU1_SA_CA<3>")
	)
	(segment
		(start 58.17235 -261.393686)
		(end 58.17235 -260.777482)
		(width 0.18288)
		(layer "In4.Cu")
		(net "M_C_CPU1_SA_CA<3>")
	)
	(segment
		(start 59.311794 -261.611872)
		(end 58.390536 -261.611872)
		(width 0.18288)
		(layer "In4.Cu")
		(net "M_C_CPU1_SA_CA<3>")
	)
	(segment
		(start 74.156824 -256.84226)
		(end 66.412872 -260.050026)
		(width 0.18288)
		(layer "In4.Cu")
		(net "M_C_CPU1_SA_CA<3>")
	)
	(segment
		(start 38.955726 -262.952738)
		(end 37.869368 -264.039096)
		(width 0.18288)
		(layer "In4.Cu")
		(net "M_C_CPU1_SA_CA<3>")
	)
	(segment
		(start 36.399216 -264.039096)
		(end 35.976814 -263.616694)
		(width 0.18288)
		(layer "In4.Cu")
		(net "M_C_CPU1_SA_CA<3>")
	)
	(segment
		(start 85.061044 -255.344676)
		(end 84.761578 -255.04521)
		(width 0.088646)
		(layer "In4.Cu")
		(net "M_C_CPU1_SA_CA<3>")
	)
	(segment
		(start 85.061044 -255.547622)
		(end 85.061044 -255.344676)
		(width 0.088646)
		(layer "In4.Cu")
		(net "M_C_CPU1_SA_CA<3>")
	)
	(segment
		(start 66.412872 -260.050026)
		(end 63.789306 -260.050026)
		(width 0.18288)
		(layer "In4.Cu")
		(net "M_C_CPU1_SA_CA<3>")
	)
	(segment
		(start 50.063146 -262.341868)
		(end 50.062892 -262.341614)
		(width 0.18288)
		(layer "In4.Cu")
		(net "M_C_CPU1_SA_CA<3>")
	)
	(segment
		(start 84.434934 -255.04521)
		(end 83.29041 -255.04521)
		(width 0.18288)
		(layer "In4.Cu")
		(net "M_C_CPU1_SA_CA<3>")
	)
	(segment
		(start 58.390536 -261.611872)
		(end 58.17235 -261.393686)
		(width 0.18288)
		(layer "In4.Cu")
		(net "M_C_CPU1_SA_CA<3>")
	)
	(segment
		(start 92.296996 -256.685796)
		(end 92.288106 -256.680716)
		(width 0.088646)
		(layer "In4.Cu")
		(net "M_C_CPU1_SA_CA<3>")
	)
	(segment
		(start 62.537848 -261.301484)
		(end 59.622182 -261.301484)
		(width 0.18288)
		(layer "In4.Cu")
		(net "M_C_CPU1_SA_CA<3>")
	)
	(segment
		(start 43.528488 -263.425432)
		(end 40.027352 -263.425432)
		(width 0.18288)
		(layer "In4.Cu")
		(net "M_C_CPU1_SA_CA<3>")
	)
	(segment
		(start 84.761578 -255.04521)
		(end 84.434934 -255.04521)
		(width 0.088646)
		(layer "In4.Cu")
		(net "M_C_CPU1_SA_CA<3>")
	)
	(segment
		(start 59.622182 -261.301484)
		(end 59.311794 -261.611872)
		(width 0.18288)
		(layer "In4.Cu")
		(net "M_C_CPU1_SA_CA<3>")
	)
	(segment
		(start 92.109544 -256.361438)
		(end 92.109544 -256.351532)
		(width 0.088646)
		(layer "In4.Cu")
		(net "M_C_CPU1_SA_CA<3>")
	)
	(segment
		(start 50.062892 -262.341614)
		(end 44.612306 -262.341614)
		(width 0.18288)
		(layer "In4.Cu")
		(net "M_C_CPU1_SA_CA<3>")
	)
	(segment
		(start 81.49336 -256.84226)
		(end 74.156824 -256.84226)
		(width 0.18288)
		(layer "In4.Cu")
		(net "M_C_CPU1_SA_CA<3>")
	)
	(segment
		(start 90.332306 -255.865884)
		(end 90.321892 -255.87198)
		(width 0.088646)
		(layer "In4.Cu")
		(net "M_C_CPU1_SA_CA<3>")
	)
	(segment
		(start 92.932758 -256.776982)
		(end 92.627196 -256.776982)
		(width 0.088646)
		(layer "In4.Cu")
		(net "M_C_CPU1_SA_CA<3>")
	)
	(segment
		(start 44.612306 -262.341614)
		(end 43.528488 -263.425432)
		(width 0.18288)
		(layer "In4.Cu")
		(net "M_C_CPU1_SA_CA<3>")
	)
	(segment
		(start 55.933086 -260.63575)
		(end 55.49138 -261.077456)
		(width 0.18288)
		(layer "In4.Cu")
		(net "M_C_CPU1_SA_CA<3>")
	)
	(segment
		(start 88.452706 -255.865884)
		(end 88.442292 -255.87198)
		(width 0.088646)
		(layer "In4.Cu")
		(net "M_C_CPU1_SA_CA<3>")
	)
	(segment
		(start 63.789306 -260.050026)
		(end 62.537848 -261.301484)
		(width 0.18288)
		(layer "In4.Cu")
		(net "M_C_CPU1_SA_CA<3>")
	)
	(segment
		(start 37.869368 -264.039096)
		(end 36.399216 -264.039096)
		(width 0.18288)
		(layer "In4.Cu")
		(net "M_C_CPU1_SA_CA<3>")
	)
	(arc
		(start 92.288106 -256.680716)
		(mid 92.157192 -256.544356)
		(end 92.109544 -256.361438)
		(width 0.088646)
		(layer "In4.Cu")
		(net "M_C_CPU1_SA_CA<3>")
	)
	(arc
		(start 89.00795 -255.87198)
		(mid 88.731137 -255.79611)
		(end 88.452706 -255.865884)
		(width 0.088646)
		(layer "In4.Cu")
		(net "M_C_CPU1_SA_CA<3>")
	)
	(arc
		(start 92.627196 -256.776982)
		(mid 92.459321 -256.754695)
		(end 92.303092 -256.689352)
		(width 0.088646)
		(layer "In4.Cu")
		(net "M_C_CPU1_SA_CA<3>")
	)
	(arc
		(start 86.562692 -255.87198)
		(mid 86.375494 -255.922123)
		(end 86.188296 -255.87198)
		(width 0.088646)
		(layer "In4.Cu")
		(net "M_C_CPU1_SA_CA<3>")
	)
	(arc
		(start 87.502492 -255.87198)
		(mid 87.315294 -255.922123)
		(end 87.128096 -255.87198)
		(width 0.088646)
		(layer "In4.Cu")
		(net "M_C_CPU1_SA_CA<3>")
	)
	(arc
		(start 86.188296 -255.87198)
		(mid 85.905594 -255.796238)
		(end 85.622892 -255.87198)
		(width 0.088646)
		(layer "In4.Cu")
		(net "M_C_CPU1_SA_CA<3>")
	)
	(arc
		(start 92.109544 -256.351532)
		(mid 92.031433 -256.074583)
		(end 91.827096 -255.87198)
		(width 0.088646)
		(layer "In4.Cu")
		(net "M_C_CPU1_SA_CA<3>")
	)
	(arc
		(start 88.067896 -255.87198)
		(mid 87.785194 -255.796204)
		(end 87.502492 -255.87198)
		(width 0.088646)
		(layer "In4.Cu")
		(net "M_C_CPU1_SA_CA<3>")
	)
	(arc
		(start 93.894148 -257.175254)
		(mid 93.453059 -256.880527)
		(end 92.932758 -256.776982)
		(width 0.088646)
		(layer "In4.Cu")
		(net "M_C_CPU1_SA_CA<3>")
	)
	(arc
		(start 85.248242 -255.871726)
		(mid 85.111197 -255.734766)
		(end 85.061044 -255.547622)
		(width 0.088646)
		(layer "In4.Cu")
		(net "M_C_CPU1_SA_CA<3>")
	)
	(arc
		(start 91.261946 -255.87198)
		(mid 91.074748 -255.922123)
		(end 90.88755 -255.87198)
		(width 0.088646)
		(layer "In4.Cu")
		(net "M_C_CPU1_SA_CA<3>")
	)
	(arc
		(start 90.321892 -255.87198)
		(mid 90.134694 -255.922123)
		(end 89.947496 -255.87198)
		(width 0.088646)
		(layer "In4.Cu")
		(net "M_C_CPU1_SA_CA<3>")
	)
	(arc
		(start 89.382346 -255.87198)
		(mid 89.195148 -255.922123)
		(end 89.00795 -255.87198)
		(width 0.088646)
		(layer "In4.Cu")
		(net "M_C_CPU1_SA_CA<3>")
	)
	(arc
		(start 89.947496 -255.87198)
		(mid 89.670937 -255.796237)
		(end 89.39276 -255.865884)
		(width 0.088646)
		(layer "In4.Cu")
		(net "M_C_CPU1_SA_CA<3>")
	)
	(arc
		(start 85.622892 -255.87198)
		(mid 85.435694 -255.922157)
		(end 85.248496 -255.87198)
		(width 0.088646)
		(layer "In4.Cu")
		(net "M_C_CPU1_SA_CA<3>")
	)
	(arc
		(start 88.442292 -255.87198)
		(mid 88.255094 -255.922123)
		(end 88.067896 -255.87198)
		(width 0.088646)
		(layer "In4.Cu")
		(net "M_C_CPU1_SA_CA<3>")
	)
	(arc
		(start 91.827096 -255.87198)
		(mid 91.550537 -255.796237)
		(end 91.27236 -255.865884)
		(width 0.088646)
		(layer "In4.Cu")
		(net "M_C_CPU1_SA_CA<3>")
	)
	(arc
		(start 90.88755 -255.87198)
		(mid 90.610737 -255.79611)
		(end 90.332306 -255.865884)
		(width 0.088646)
		(layer "In4.Cu")
		(net "M_C_CPU1_SA_CA<3>")
	)
	(arc
		(start 87.128096 -255.87198)
		(mid 86.845394 -255.796204)
		(end 86.562692 -255.87198)
		(width 0.088646)
		(layer "In4.Cu")
		(net "M_C_CPU1_SA_CA<3>")
	)
	(segment
		(start 26.20391 -264.032746)
		(end 26.2128 -264.041636)
		(width 0.1016)
		(layer "F.Cu")
		(net "M_C_CPU1_SA_CA<2>")
	)
	(segment
		(start 28.198318 -264.041636)
		(end 28.529026 -264.041636)
		(width 0.101854)
		(layer "F.Cu")
		(net "M_C_CPU1_SA_CA<2>")
	)
	(segment
		(start 24.562308 -264.466578)
		(end 24.773636 -264.677906)
		(width 0.20066)
		(layer "F.Cu")
		(net "M_C_CPU1_SA_CA<2>")
	)
	(segment
		(start 28.529026 -264.041636)
		(end 28.707588 -264.041636)
		(width 0.20066)
		(layer "F.Cu")
		(net "M_C_CPU1_SA_CA<2>")
	)
	(segment
		(start 24.773636 -264.677906)
		(end 25.27808 -264.677906)
		(width 0.20066)
		(layer "F.Cu")
		(net "M_C_CPU1_SA_CA<2>")
	)
	(segment
		(start 25.27808 -264.677906)
		(end 25.432512 -264.523474)
		(width 0.20066)
		(layer "F.Cu")
		(net "M_C_CPU1_SA_CA<2>")
	)
	(segment
		(start 25.432512 -264.523474)
		(end 25.432512 -264.195306)
		(width 0.20066)
		(layer "F.Cu")
		(net "M_C_CPU1_SA_CA<2>")
	)
	(segment
		(start 25.595072 -264.032746)
		(end 26.20391 -264.032746)
		(width 0.20066)
		(layer "F.Cu")
		(net "M_C_CPU1_SA_CA<2>")
	)
	(segment
		(start 26.2128 -264.041636)
		(end 28.198318 -264.041636)
		(width 0.1016)
		(layer "F.Cu")
		(net "M_C_CPU1_SA_CA<2>")
	)
	(segment
		(start 92.014294 -256.639314)
		(end 92.014294 -257.175)
		(width 0.20066)
		(layer "F.Cu")
		(net "M_C_CPU1_SA_CA<2>")
	)
	(segment
		(start 31.876746 -264.466578)
		(end 30.771846 -264.466578)
		(width 0.20066)
		(layer "F.Cu")
		(net "M_C_CPU1_SA_CA<2>")
	)
	(segment
		(start 29.13253 -264.466578)
		(end 30.771846 -264.466578)
		(width 0.20066)
		(layer "F.Cu")
		(net "M_C_CPU1_SA_CA<2>")
	)
	(segment
		(start 23.228046 -264.466578)
		(end 24.562308 -264.466578)
		(width 0.20066)
		(layer "F.Cu")
		(net "M_C_CPU1_SA_CA<2>")
	)
	(segment
		(start 25.432512 -264.195306)
		(end 25.595072 -264.032746)
		(width 0.20066)
		(layer "F.Cu")
		(net "M_C_CPU1_SA_CA<2>")
	)
	(segment
		(start 28.707588 -264.041636)
		(end 29.13253 -264.466578)
		(width 0.20066)
		(layer "F.Cu")
		(net "M_C_CPU1_SA_CA<2>")
	)
	(segment
		(start 92.014294 -257.175)
		(end 92.014548 -257.175254)
		(width 0.20066)
		(layer "F.Cu")
		(net "M_C_CPU1_SA_CA<2>")
	)
	(segment
		(start 65.54597 -260.800596)
		(end 64.683386 -261.66318)
		(width 0.18288)
		(layer "In4.Cu")
		(net "M_C_CPU1_SA_CA<2>")
	)
	(segment
		(start 56.629046 -261.808214)
		(end 55.245508 -263.191752)
		(width 0.18288)
		(layer "In4.Cu")
		(net "M_C_CPU1_SA_CA<2>")
	)
	(segment
		(start 65.983612 -260.61924)
		(end 65.54597 -260.800596)
		(width 0.18288)
		(layer "In4.Cu")
		(net "M_C_CPU1_SA_CA<2>")
	)
	(segment
		(start 89.477596 -256.03708)
		(end 89.462864 -256.045716)
		(width 0.088646)
		(layer "In4.Cu")
		(net "M_C_CPU1_SA_CA<2>")
	)
	(segment
		(start 92.014548 -257.175254)
		(end 91.919044 -257.07975)
		(width 0.088646)
		(layer "In4.Cu")
		(net "M_C_CPU1_SA_CA<2>")
	)
	(segment
		(start 81.862168 -257.17754)
		(end 74.710544 -257.17754)
		(width 0.18288)
		(layer "In4.Cu")
		(net "M_C_CPU1_SA_CA<2>")
	)
	(segment
		(start 91.740482 -256.04216)
		(end 91.731592 -256.03708)
		(width 0.088646)
		(layer "In4.Cu")
		(net "M_C_CPU1_SA_CA<2>")
	)
	(segment
		(start 84.284058 -255.971548)
		(end 84.058252 -255.745742)
		(width 0.18288)
		(layer "In4.Cu")
		(net "M_C_CPU1_SA_CA<2>")
	)
	(segment
		(start 85.147658 -256.112772)
		(end 85.006434 -255.971548)
		(width 0.088646)
		(layer "In4.Cu")
		(net "M_C_CPU1_SA_CA<2>")
	)
	(segment
		(start 74.710544 -257.17754)
		(end 66.401442 -260.61924)
		(width 0.18288)
		(layer "In4.Cu")
		(net "M_C_CPU1_SA_CA<2>")
	)
	(segment
		(start 57.791096 -261.808214)
		(end 56.629046 -261.808214)
		(width 0.18288)
		(layer "In4.Cu")
		(net "M_C_CPU1_SA_CA<2>")
	)
	(segment
		(start 91.919044 -257.07975)
		(end 91.919044 -256.361438)
		(width 0.088646)
		(layer "In4.Cu")
		(net "M_C_CPU1_SA_CA<2>")
	)
	(segment
		(start 59.385708 -262.54964)
		(end 58.993024 -262.156956)
		(width 0.18288)
		(layer "In4.Cu")
		(net "M_C_CPU1_SA_CA<2>")
	)
	(segment
		(start 38.211252 -264.893806)
		(end 32.303974 -264.893806)
		(width 0.18288)
		(layer "In4.Cu")
		(net "M_C_CPU1_SA_CA<2>")
	)
	(segment
		(start 63.316612 -261.66318)
		(end 62.430152 -262.54964)
		(width 0.18288)
		(layer "In4.Cu")
		(net "M_C_CPU1_SA_CA<2>")
	)
	(segment
		(start 55.245508 -263.191752)
		(end 44.501308 -263.191752)
		(width 0.18288)
		(layer "In4.Cu")
		(net "M_C_CPU1_SA_CA<2>")
	)
	(segment
		(start 85.435694 -256.112772)
		(end 85.147658 -256.112772)
		(width 0.088646)
		(layer "In4.Cu")
		(net "M_C_CPU1_SA_CA<2>")
	)
	(segment
		(start 64.683386 -261.66318)
		(end 63.316612 -261.66318)
		(width 0.18288)
		(layer "In4.Cu")
		(net "M_C_CPU1_SA_CA<2>")
	)
	(segment
		(start 91.357196 -256.03708)
		(end 91.342464 -256.045716)
		(width 0.088646)
		(layer "In4.Cu")
		(net "M_C_CPU1_SA_CA<2>")
	)
	(segment
		(start 58.993024 -262.156956)
		(end 58.139838 -262.156956)
		(width 0.18288)
		(layer "In4.Cu")
		(net "M_C_CPU1_SA_CA<2>")
	)
	(segment
		(start 32.303974 -264.893806)
		(end 31.876746 -264.466578)
		(width 0.18288)
		(layer "In4.Cu")
		(net "M_C_CPU1_SA_CA<2>")
	)
	(segment
		(start 66.401442 -260.61924)
		(end 65.983612 -260.61924)
		(width 0.18288)
		(layer "In4.Cu")
		(net "M_C_CPU1_SA_CA<2>")
	)
	(segment
		(start 39.063422 -264.041636)
		(end 38.211252 -264.893806)
		(width 0.18288)
		(layer "In4.Cu")
		(net "M_C_CPU1_SA_CA<2>")
	)
	(segment
		(start 84.434934 -255.971548)
		(end 84.284058 -255.971548)
		(width 0.18288)
		(layer "In4.Cu")
		(net "M_C_CPU1_SA_CA<2>")
	)
	(segment
		(start 58.139838 -262.156956)
		(end 57.791096 -261.808214)
		(width 0.18288)
		(layer "In4.Cu")
		(net "M_C_CPU1_SA_CA<2>")
	)
	(segment
		(start 83.293966 -255.745742)
		(end 81.862168 -257.17754)
		(width 0.18288)
		(layer "In4.Cu")
		(net "M_C_CPU1_SA_CA<2>")
	)
	(segment
		(start 85.006434 -255.971548)
		(end 84.434934 -255.971548)
		(width 0.088646)
		(layer "In4.Cu")
		(net "M_C_CPU1_SA_CA<2>")
	)
	(segment
		(start 43.651424 -264.041636)
		(end 39.063422 -264.041636)
		(width 0.18288)
		(layer "In4.Cu")
		(net "M_C_CPU1_SA_CA<2>")
	)
	(segment
		(start 62.430152 -262.54964)
		(end 59.385708 -262.54964)
		(width 0.18288)
		(layer "In4.Cu")
		(net "M_C_CPU1_SA_CA<2>")
	)
	(segment
		(start 84.058252 -255.745742)
		(end 83.293966 -255.745742)
		(width 0.18288)
		(layer "In4.Cu")
		(net "M_C_CPU1_SA_CA<2>")
	)
	(segment
		(start 44.501308 -263.191752)
		(end 43.651424 -264.041636)
		(width 0.18288)
		(layer "In4.Cu")
		(net "M_C_CPU1_SA_CA<2>")
	)
	(arc
		(start 86.658196 -256.03708)
		(mid 86.375494 -256.112856)
		(end 86.092792 -256.03708)
		(width 0.088646)
		(layer "In4.Cu")
		(net "M_C_CPU1_SA_CA<2>")
	)
	(arc
		(start 87.972392 -256.03708)
		(mid 87.785194 -255.986937)
		(end 87.597996 -256.03708)
		(width 0.088646)
		(layer "In4.Cu")
		(net "M_C_CPU1_SA_CA<2>")
	)
	(arc
		(start 87.597996 -256.03708)
		(mid 87.315294 -256.112856)
		(end 87.032592 -256.03708)
		(width 0.088646)
		(layer "In4.Cu")
		(net "M_C_CPU1_SA_CA<2>")
	)
	(arc
		(start 90.417396 -256.03708)
		(mid 90.134694 -256.112856)
		(end 89.851992 -256.03708)
		(width 0.088646)
		(layer "In4.Cu")
		(net "M_C_CPU1_SA_CA<2>")
	)
	(arc
		(start 90.791792 -256.03708)
		(mid 90.604594 -255.986937)
		(end 90.417396 -256.03708)
		(width 0.088646)
		(layer "In4.Cu")
		(net "M_C_CPU1_SA_CA<2>")
	)
	(arc
		(start 88.537796 -256.03708)
		(mid 88.255094 -256.112856)
		(end 87.972392 -256.03708)
		(width 0.088646)
		(layer "In4.Cu")
		(net "M_C_CPU1_SA_CA<2>")
	)
	(arc
		(start 91.731592 -256.03708)
		(mid 91.544394 -255.986937)
		(end 91.357196 -256.03708)
		(width 0.088646)
		(layer "In4.Cu")
		(net "M_C_CPU1_SA_CA<2>")
	)
	(arc
		(start 85.718396 -256.03708)
		(mid 85.582027 -256.093522)
		(end 85.435694 -256.112772)
		(width 0.088646)
		(layer "In4.Cu")
		(net "M_C_CPU1_SA_CA<2>")
	)
	(arc
		(start 89.462864 -256.045716)
		(mid 89.186389 -256.113036)
		(end 88.912192 -256.03708)
		(width 0.088646)
		(layer "In4.Cu")
		(net "M_C_CPU1_SA_CA<2>")
	)
	(arc
		(start 88.912192 -256.03708)
		(mid 88.724994 -255.986937)
		(end 88.537796 -256.03708)
		(width 0.088646)
		(layer "In4.Cu")
		(net "M_C_CPU1_SA_CA<2>")
	)
	(arc
		(start 91.342464 -256.045716)
		(mid 91.065989 -256.113036)
		(end 90.791792 -256.03708)
		(width 0.088646)
		(layer "In4.Cu")
		(net "M_C_CPU1_SA_CA<2>")
	)
	(arc
		(start 89.851992 -256.03708)
		(mid 89.664794 -255.986937)
		(end 89.477596 -256.03708)
		(width 0.088646)
		(layer "In4.Cu")
		(net "M_C_CPU1_SA_CA<2>")
	)
	(arc
		(start 86.092792 -256.03708)
		(mid 85.905594 -255.986937)
		(end 85.718396 -256.03708)
		(width 0.088646)
		(layer "In4.Cu")
		(net "M_C_CPU1_SA_CA<2>")
	)
	(arc
		(start 91.919044 -256.361438)
		(mid 91.871365 -256.178538)
		(end 91.740482 -256.04216)
		(width 0.088646)
		(layer "In4.Cu")
		(net "M_C_CPU1_SA_CA<2>")
	)
	(arc
		(start 87.032592 -256.03708)
		(mid 86.845394 -255.986937)
		(end 86.658196 -256.03708)
		(width 0.088646)
		(layer "In4.Cu")
		(net "M_C_CPU1_SA_CA<2>")
	)
	(segment
		(start 94.364048 -257.45313)
		(end 94.364048 -257.988816)
		(width 0.20066)
		(layer "F.Cu")
		(net "M_C_CPU1_SA_CA<1>")
	)
	(segment
		(start 31.972758 -265.741658)
		(end 32.51708 -265.741658)
		(width 0.20066)
		(layer "F.Cu")
		(net "M_C_CPU1_SA_CA<1>")
	)
	(segment
		(start 33.189926 -265.312398)
		(end 33.401762 -265.524234)
		(width 0.20066)
		(layer "F.Cu")
		(net "M_C_CPU1_SA_CA<1>")
	)
	(segment
		(start 32.666178 -265.59256)
		(end 32.666178 -265.440922)
		(width 0.20066)
		(layer "F.Cu")
		(net "M_C_CPU1_SA_CA<1>")
	)
	(segment
		(start 32.794702 -265.312398)
		(end 33.189926 -265.312398)
		(width 0.20066)
		(layer "F.Cu")
		(net "M_C_CPU1_SA_CA<1>")
	)
	(segment
		(start 27.328114 -265.316716)
		(end 29.025342 -265.316716)
		(width 0.20066)
		(layer "F.Cu")
		(net "M_C_CPU1_SA_CA<1>")
	)
	(segment
		(start 29.025342 -265.316716)
		(end 29.151326 -265.4427)
		(width 0.20066)
		(layer "F.Cu")
		(net "M_C_CPU1_SA_CA<1>")
	)
	(segment
		(start 29.151326 -265.4427)
		(end 29.151326 -265.613388)
		(width 0.20066)
		(layer "F.Cu")
		(net "M_C_CPU1_SA_CA<1>")
	)
	(segment
		(start 94.364048 -257.988816)
		(end 94.363794 -257.98907)
		(width 0.20066)
		(layer "F.Cu")
		(net "M_C_CPU1_SA_CA<1>")
	)
	(segment
		(start 32.666178 -265.440922)
		(end 32.794702 -265.312398)
		(width 0.20066)
		(layer "F.Cu")
		(net "M_C_CPU1_SA_CA<1>")
	)
	(segment
		(start 33.401762 -265.524234)
		(end 33.848294 -265.524234)
		(width 0.20066)
		(layer "F.Cu")
		(net "M_C_CPU1_SA_CA<1>")
	)
	(segment
		(start 34.055812 -265.316716)
		(end 34.871914 -265.316716)
		(width 0.20066)
		(layer "F.Cu")
		(net "M_C_CPU1_SA_CA<1>")
	)
	(segment
		(start 29.661866 -265.741658)
		(end 29.899864 -265.741658)
		(width 0.101854)
		(layer "F.Cu")
		(net "M_C_CPU1_SA_CA<1>")
	)
	(segment
		(start 29.29382 -265.755882)
		(end 29.647642 -265.755882)
		(width 0.20066)
		(layer "F.Cu")
		(net "M_C_CPU1_SA_CA<1>")
	)
	(segment
		(start 35.976814 -265.316716)
		(end 34.871914 -265.316716)
		(width 0.20066)
		(layer "F.Cu")
		(net "M_C_CPU1_SA_CA<1>")
	)
	(segment
		(start 32.51708 -265.741658)
		(end 32.666178 -265.59256)
		(width 0.20066)
		(layer "F.Cu")
		(net "M_C_CPU1_SA_CA<1>")
	)
	(segment
		(start 33.848294 -265.524234)
		(end 34.055812 -265.316716)
		(width 0.20066)
		(layer "F.Cu")
		(net "M_C_CPU1_SA_CA<1>")
	)
	(segment
		(start 29.899864 -265.741658)
		(end 31.972758 -265.741658)
		(width 0.1016)
		(layer "F.Cu")
		(net "M_C_CPU1_SA_CA<1>")
	)
	(segment
		(start 29.647642 -265.755882)
		(end 29.661866 -265.741658)
		(width 0.101854)
		(layer "F.Cu")
		(net "M_C_CPU1_SA_CA<1>")
	)
	(segment
		(start 29.151326 -265.613388)
		(end 29.29382 -265.755882)
		(width 0.20066)
		(layer "F.Cu")
		(net "M_C_CPU1_SA_CA<1>")
	)
	(segment
		(start 82.23123 -257.51282)
		(end 75.238356 -257.51282)
		(width 0.18288)
		(layer "In4.Cu")
		(net "M_C_CPU1_SA_CA<1>")
	)
	(segment
		(start 43.606212 -265.102848)
		(end 39.99738 -265.102848)
		(width 0.18288)
		(layer "In4.Cu")
		(net "M_C_CPU1_SA_CA<1>")
	)
	(segment
		(start 39.99738 -265.102848)
		(end 39.775638 -264.881106)
		(width 0.18288)
		(layer "In4.Cu")
		(net "M_C_CPU1_SA_CA<1>")
	)
	(segment
		(start 55.29199 -264.041636)
		(end 44.667424 -264.041636)
		(width 0.18288)
		(layer "In4.Cu")
		(net "M_C_CPU1_SA_CA<1>")
	)
	(segment
		(start 91.97848 -257.585972)
		(end 91.81846 -257.494532)
		(width 0.088646)
		(layer "In4.Cu")
		(net "M_C_CPU1_SA_CA<1>")
	)
	(segment
		(start 60.247022 -263.064244)
		(end 59.412378 -263.064244)
		(width 0.18288)
		(layer "In4.Cu")
		(net "M_C_CPU1_SA_CA<1>")
	)
	(segment
		(start 94.363794 -257.98907)
		(end 93.684852 -257.585972)
		(width 0.088646)
		(layer "In4.Cu")
		(net "M_C_CPU1_SA_CA<1>")
	)
	(segment
		(start 64.901572 -262.186928)
		(end 63.772542 -262.186928)
		(width 0.18288)
		(layer "In4.Cu")
		(net "M_C_CPU1_SA_CA<1>")
	)
	(segment
		(start 56.820054 -263.410446)
		(end 55.92318 -263.410446)
		(width 0.18288)
		(layer "In4.Cu")
		(net "M_C_CPU1_SA_CA<1>")
	)
	(segment
		(start 57.876694 -263.410446)
		(end 57.693814 -263.227566)
		(width 0.18288)
		(layer "In4.Cu")
		(net "M_C_CPU1_SA_CA<1>")
	)
	(segment
		(start 60.429902 -263.315958)
		(end 60.429902 -263.247124)
		(width 0.18288)
		(layer "In4.Cu")
		(net "M_C_CPU1_SA_CA<1>")
	)
	(segment
		(start 60.429902 -263.247124)
		(end 60.247022 -263.064244)
		(width 0.18288)
		(layer "In4.Cu")
		(net "M_C_CPU1_SA_CA<1>")
	)
	(segment
		(start 36.413186 -265.753088)
		(end 35.976814 -265.316716)
		(width 0.18288)
		(layer "In4.Cu")
		(net "M_C_CPU1_SA_CA<1>")
	)
	(segment
		(start 57.693814 -263.227566)
		(end 57.693814 -262.776462)
		(width 0.18288)
		(layer "In4.Cu")
		(net "M_C_CPU1_SA_CA<1>")
	)
	(segment
		(start 57.693814 -262.776462)
		(end 57.510934 -262.593582)
		(width 0.18288)
		(layer "In4.Cu")
		(net "M_C_CPU1_SA_CA<1>")
	)
	(segment
		(start 55.92318 -263.410446)
		(end 55.29199 -264.041636)
		(width 0.18288)
		(layer "In4.Cu")
		(net "M_C_CPU1_SA_CA<1>")
	)
	(segment
		(start 66.97091 -260.937502)
		(end 66.301112 -261.6073)
		(width 0.18288)
		(layer "In4.Cu")
		(net "M_C_CPU1_SA_CA<1>")
	)
	(segment
		(start 85.063838 -256.610104)
		(end 84.923376 -256.469642)
		(width 0.088646)
		(layer "In4.Cu")
		(net "M_C_CPU1_SA_CA<1>")
	)
	(segment
		(start 83.274408 -256.469642)
		(end 82.23123 -257.51282)
		(width 0.18288)
		(layer "In4.Cu")
		(net "M_C_CPU1_SA_CA<1>")
	)
	(segment
		(start 84.434934 -256.469642)
		(end 83.274408 -256.469642)
		(width 0.18288)
		(layer "In4.Cu")
		(net "M_C_CPU1_SA_CA<1>")
	)
	(segment
		(start 63.772542 -262.186928)
		(end 62.895226 -263.064244)
		(width 0.18288)
		(layer "In4.Cu")
		(net "M_C_CPU1_SA_CA<1>")
	)
	(segment
		(start 61.120782 -263.315958)
		(end 60.937902 -263.498838)
		(width 0.18288)
		(layer "In4.Cu")
		(net "M_C_CPU1_SA_CA<1>")
	)
	(segment
		(start 61.303662 -263.064244)
		(end 61.120782 -263.247124)
		(width 0.18288)
		(layer "In4.Cu")
		(net "M_C_CPU1_SA_CA<1>")
	)
	(segment
		(start 38.379908 -265.753088)
		(end 36.413186 -265.753088)
		(width 0.18288)
		(layer "In4.Cu")
		(net "M_C_CPU1_SA_CA<1>")
	)
	(segment
		(start 91.369388 -256.692908)
		(end 91.357196 -256.685796)
		(width 0.088646)
		(layer "In4.Cu")
		(net "M_C_CPU1_SA_CA<1>")
	)
	(segment
		(start 60.937902 -263.498838)
		(end 60.612782 -263.498838)
		(width 0.18288)
		(layer "In4.Cu")
		(net "M_C_CPU1_SA_CA<1>")
	)
	(segment
		(start 57.002934 -262.776462)
		(end 57.002934 -263.227566)
		(width 0.18288)
		(layer "In4.Cu")
		(net "M_C_CPU1_SA_CA<1>")
	)
	(segment
		(start 60.612782 -263.498838)
		(end 60.429902 -263.315958)
		(width 0.18288)
		(layer "In4.Cu")
		(net "M_C_CPU1_SA_CA<1>")
	)
	(segment
		(start 93.684852 -257.585972)
		(end 91.97848 -257.585972)
		(width 0.088646)
		(layer "In4.Cu")
		(net "M_C_CPU1_SA_CA<1>")
	)
	(segment
		(start 39.25189 -264.881106)
		(end 38.379908 -265.753088)
		(width 0.18288)
		(layer "In4.Cu")
		(net "M_C_CPU1_SA_CA<1>")
	)
	(segment
		(start 61.120782 -263.247124)
		(end 61.120782 -263.315958)
		(width 0.18288)
		(layer "In4.Cu")
		(net "M_C_CPU1_SA_CA<1>")
	)
	(segment
		(start 66.301112 -261.6073)
		(end 64.901572 -262.186928)
		(width 0.18288)
		(layer "In4.Cu")
		(net "M_C_CPU1_SA_CA<1>")
	)
	(segment
		(start 59.412378 -263.064244)
		(end 59.066176 -263.410446)
		(width 0.18288)
		(layer "In4.Cu")
		(net "M_C_CPU1_SA_CA<1>")
	)
	(segment
		(start 62.895226 -263.064244)
		(end 61.303662 -263.064244)
		(width 0.18288)
		(layer "In4.Cu")
		(net "M_C_CPU1_SA_CA<1>")
	)
	(segment
		(start 57.510934 -262.593582)
		(end 57.185814 -262.593582)
		(width 0.18288)
		(layer "In4.Cu")
		(net "M_C_CPU1_SA_CA<1>")
	)
	(segment
		(start 85.435694 -256.610104)
		(end 85.063838 -256.610104)
		(width 0.088646)
		(layer "In4.Cu")
		(net "M_C_CPU1_SA_CA<1>")
	)
	(segment
		(start 59.066176 -263.410446)
		(end 57.876694 -263.410446)
		(width 0.18288)
		(layer "In4.Cu")
		(net "M_C_CPU1_SA_CA<1>")
	)
	(segment
		(start 57.185814 -262.593582)
		(end 57.002934 -262.776462)
		(width 0.18288)
		(layer "In4.Cu")
		(net "M_C_CPU1_SA_CA<1>")
	)
	(segment
		(start 44.667424 -264.041636)
		(end 43.606212 -265.102848)
		(width 0.18288)
		(layer "In4.Cu")
		(net "M_C_CPU1_SA_CA<1>")
	)
	(segment
		(start 39.775638 -264.881106)
		(end 39.25189 -264.881106)
		(width 0.18288)
		(layer "In4.Cu")
		(net "M_C_CPU1_SA_CA<1>")
	)
	(segment
		(start 57.002934 -263.227566)
		(end 56.820054 -263.410446)
		(width 0.18288)
		(layer "In4.Cu")
		(net "M_C_CPU1_SA_CA<1>")
	)
	(segment
		(start 84.923376 -256.469642)
		(end 84.434934 -256.469642)
		(width 0.088646)
		(layer "In4.Cu")
		(net "M_C_CPU1_SA_CA<1>")
	)
	(segment
		(start 75.238356 -257.51282)
		(end 66.97091 -260.937502)
		(width 0.18288)
		(layer "In4.Cu")
		(net "M_C_CPU1_SA_CA<1>")
	)
	(arc
		(start 91.639898 -257.175254)
		(mid 91.567663 -256.89873)
		(end 91.369388 -256.692908)
		(width 0.088646)
		(layer "In4.Cu")
		(net "M_C_CPU1_SA_CA<1>")
	)
	(arc
		(start 90.791792 -256.685796)
		(mid 90.604594 -256.735939)
		(end 90.417396 -256.685796)
		(width 0.088646)
		(layer "In4.Cu")
		(net "M_C_CPU1_SA_CA<1>")
	)
	(arc
		(start 90.417396 -256.685796)
		(mid 90.134694 -256.61002)
		(end 89.851992 -256.685796)
		(width 0.088646)
		(layer "In4.Cu")
		(net "M_C_CPU1_SA_CA<1>")
	)
	(arc
		(start 87.972392 -256.685796)
		(mid 87.785194 -256.735939)
		(end 87.597996 -256.685796)
		(width 0.088646)
		(layer "In4.Cu")
		(net "M_C_CPU1_SA_CA<1>")
	)
	(arc
		(start 89.851992 -256.685796)
		(mid 89.664794 -256.735939)
		(end 89.477596 -256.685796)
		(width 0.088646)
		(layer "In4.Cu")
		(net "M_C_CPU1_SA_CA<1>")
	)
	(arc
		(start 87.597996 -256.685796)
		(mid 87.315294 -256.61002)
		(end 87.032592 -256.685796)
		(width 0.088646)
		(layer "In4.Cu")
		(net "M_C_CPU1_SA_CA<1>")
	)
	(arc
		(start 87.032592 -256.685796)
		(mid 86.845394 -256.735939)
		(end 86.658196 -256.685796)
		(width 0.088646)
		(layer "In4.Cu")
		(net "M_C_CPU1_SA_CA<1>")
	)
	(arc
		(start 91.357196 -256.685796)
		(mid 91.074494 -256.61002)
		(end 90.791792 -256.685796)
		(width 0.088646)
		(layer "In4.Cu")
		(net "M_C_CPU1_SA_CA<1>")
	)
	(arc
		(start 91.81846 -257.494532)
		(mid 91.687546 -257.358172)
		(end 91.639898 -257.175254)
		(width 0.088646)
		(layer "In4.Cu")
		(net "M_C_CPU1_SA_CA<1>")
	)
	(arc
		(start 88.912192 -256.685796)
		(mid 88.724994 -256.735939)
		(end 88.537796 -256.685796)
		(width 0.088646)
		(layer "In4.Cu")
		(net "M_C_CPU1_SA_CA<1>")
	)
	(arc
		(start 89.477596 -256.685796)
		(mid 89.194894 -256.61002)
		(end 88.912192 -256.685796)
		(width 0.088646)
		(layer "In4.Cu")
		(net "M_C_CPU1_SA_CA<1>")
	)
	(arc
		(start 85.718396 -256.685796)
		(mid 85.582027 -256.629354)
		(end 85.435694 -256.610104)
		(width 0.088646)
		(layer "In4.Cu")
		(net "M_C_CPU1_SA_CA<1>")
	)
	(arc
		(start 86.658196 -256.685796)
		(mid 86.375494 -256.61002)
		(end 86.092792 -256.685796)
		(width 0.088646)
		(layer "In4.Cu")
		(net "M_C_CPU1_SA_CA<1>")
	)
	(arc
		(start 88.537796 -256.685796)
		(mid 88.255094 -256.61002)
		(end 87.972392 -256.685796)
		(width 0.088646)
		(layer "In4.Cu")
		(net "M_C_CPU1_SA_CA<1>")
	)
	(arc
		(start 86.092792 -256.685796)
		(mid 85.905594 -256.735939)
		(end 85.718396 -256.685796)
		(width 0.088646)
		(layer "In4.Cu")
		(net "M_C_CPU1_SA_CA<1>")
	)
	(segment
		(start 25.595072 -265.732768)
		(end 26.20391 -265.732768)
		(width 0.20066)
		(layer "F.Cu")
		(net "M_C_CPU1_SA_CA<0>")
	)
	(segment
		(start 28.707588 -265.741658)
		(end 29.13253 -266.1666)
		(width 0.20066)
		(layer "F.Cu")
		(net "M_C_CPU1_SA_CA<0>")
	)
	(segment
		(start 91.544648 -257.988816)
		(end 91.544394 -257.98907)
		(width 0.20066)
		(layer "F.Cu")
		(net "M_C_CPU1_SA_CA<0>")
	)
	(segment
		(start 25.432512 -266.223496)
		(end 25.432512 -265.895328)
		(width 0.20066)
		(layer "F.Cu")
		(net "M_C_CPU1_SA_CA<0>")
	)
	(segment
		(start 24.562308 -266.1666)
		(end 24.773636 -266.377928)
		(width 0.20066)
		(layer "F.Cu")
		(net "M_C_CPU1_SA_CA<0>")
	)
	(segment
		(start 26.20391 -265.732768)
		(end 26.2128 -265.741658)
		(width 0.1016)
		(layer "F.Cu")
		(net "M_C_CPU1_SA_CA<0>")
	)
	(segment
		(start 28.198318 -265.741658)
		(end 28.529026 -265.741658)
		(width 0.101854)
		(layer "F.Cu")
		(net "M_C_CPU1_SA_CA<0>")
	)
	(segment
		(start 23.228046 -266.1666)
		(end 24.562308 -266.1666)
		(width 0.20066)
		(layer "F.Cu")
		(net "M_C_CPU1_SA_CA<0>")
	)
	(segment
		(start 28.529026 -265.741658)
		(end 28.707588 -265.741658)
		(width 0.20066)
		(layer "F.Cu")
		(net "M_C_CPU1_SA_CA<0>")
	)
	(segment
		(start 91.544648 -257.45313)
		(end 91.544648 -257.988816)
		(width 0.20066)
		(layer "F.Cu")
		(net "M_C_CPU1_SA_CA<0>")
	)
	(segment
		(start 24.773636 -266.377928)
		(end 25.27808 -266.377928)
		(width 0.20066)
		(layer "F.Cu")
		(net "M_C_CPU1_SA_CA<0>")
	)
	(segment
		(start 25.27808 -266.377928)
		(end 25.432512 -266.223496)
		(width 0.20066)
		(layer "F.Cu")
		(net "M_C_CPU1_SA_CA<0>")
	)
	(segment
		(start 31.876746 -266.1666)
		(end 30.771846 -266.1666)
		(width 0.20066)
		(layer "F.Cu")
		(net "M_C_CPU1_SA_CA<0>")
	)
	(segment
		(start 25.432512 -265.895328)
		(end 25.595072 -265.732768)
		(width 0.20066)
		(layer "F.Cu")
		(net "M_C_CPU1_SA_CA<0>")
	)
	(segment
		(start 26.2128 -265.741658)
		(end 28.198318 -265.741658)
		(width 0.1016)
		(layer "F.Cu")
		(net "M_C_CPU1_SA_CA<0>")
	)
	(segment
		(start 29.13253 -266.1666)
		(end 30.771846 -266.1666)
		(width 0.20066)
		(layer "F.Cu")
		(net "M_C_CPU1_SA_CA<0>")
	)
	(segment
		(start 39.122096 -266.590526)
		(end 35.704018 -266.590526)
		(width 0.18288)
		(layer "In4.Cu")
		(net "M_C_CPU1_SA_CA<0>")
	)
	(segment
		(start 35.704018 -266.590526)
		(end 34.85515 -265.741658)
		(width 0.18288)
		(layer "In4.Cu")
		(net "M_C_CPU1_SA_CA<0>")
	)
	(segment
		(start 32.301688 -265.741658)
		(end 31.876746 -266.1666)
		(width 0.18288)
		(layer "In4.Cu")
		(net "M_C_CPU1_SA_CA<0>")
	)
	(segment
		(start 59.403742 -263.933686)
		(end 56.12638 -263.933686)
		(width 0.18288)
		(layer "In4.Cu")
		(net "M_C_CPU1_SA_CA<0>")
	)
	(segment
		(start 34.85515 -265.741658)
		(end 32.301688 -265.741658)
		(width 0.18288)
		(layer "In4.Cu")
		(net "M_C_CPU1_SA_CA<0>")
	)
	(segment
		(start 91.270582 -256.855976)
		(end 91.261692 -256.850896)
		(width 0.088646)
		(layer "In4.Cu")
		(net "M_C_CPU1_SA_CA<0>")
	)
	(segment
		(start 67.303396 -261.344664)
		(end 66.518282 -262.129778)
		(width 0.18288)
		(layer "In4.Cu")
		(net "M_C_CPU1_SA_CA<0>")
	)
	(segment
		(start 75.744578 -257.8481)
		(end 67.303396 -261.344664)
		(width 0.18288)
		(layer "In4.Cu")
		(net "M_C_CPU1_SA_CA<0>")
	)
	(segment
		(start 85.435694 -256.80035)
		(end 85.10651 -256.80035)
		(width 0.088646)
		(layer "In4.Cu")
		(net "M_C_CPU1_SA_CA<0>")
	)
	(segment
		(start 64.32296 -263.330944)
		(end 63.544196 -263.330944)
		(width 0.18288)
		(layer "In4.Cu")
		(net "M_C_CPU1_SA_CA<0>")
	)
	(segment
		(start 62.7888 -264.08634)
		(end 59.556396 -264.08634)
		(width 0.18288)
		(layer "In4.Cu")
		(net "M_C_CPU1_SA_CA<0>")
	)
	(segment
		(start 82.636106 -257.8481)
		(end 75.744578 -257.8481)
		(width 0.18288)
		(layer "In4.Cu")
		(net "M_C_CPU1_SA_CA<0>")
	)
	(segment
		(start 55.168292 -264.891774)
		(end 44.553886 -264.891774)
		(width 0.18288)
		(layer "In4.Cu")
		(net "M_C_CPU1_SA_CA<0>")
	)
	(segment
		(start 56.12638 -263.933686)
		(end 55.168292 -264.891774)
		(width 0.18288)
		(layer "In4.Cu")
		(net "M_C_CPU1_SA_CA<0>")
	)
	(segment
		(start 63.544196 -263.330944)
		(end 62.7888 -264.08634)
		(width 0.18288)
		(layer "In4.Cu")
		(net "M_C_CPU1_SA_CA<0>")
	)
	(segment
		(start 44.553886 -264.891774)
		(end 43.775884 -265.669776)
		(width 0.18288)
		(layer "In4.Cu")
		(net "M_C_CPU1_SA_CA<0>")
	)
	(segment
		(start 40.042846 -265.669776)
		(end 39.122096 -266.590526)
		(width 0.18288)
		(layer "In4.Cu")
		(net "M_C_CPU1_SA_CA<0>")
	)
	(segment
		(start 84.999068 -256.907792)
		(end 84.434934 -256.907792)
		(width 0.088646)
		(layer "In4.Cu")
		(net "M_C_CPU1_SA_CA<0>")
	)
	(segment
		(start 59.556396 -264.08634)
		(end 59.403742 -263.933686)
		(width 0.18288)
		(layer "In4.Cu")
		(net "M_C_CPU1_SA_CA<0>")
	)
	(segment
		(start 85.10651 -256.80035)
		(end 84.999068 -256.907792)
		(width 0.088646)
		(layer "In4.Cu")
		(net "M_C_CPU1_SA_CA<0>")
	)
	(segment
		(start 66.518282 -262.129778)
		(end 64.821054 -262.83285)
		(width 0.18288)
		(layer "In4.Cu")
		(net "M_C_CPU1_SA_CA<0>")
	)
	(segment
		(start 83.576414 -256.907792)
		(end 82.636106 -257.8481)
		(width 0.18288)
		(layer "In4.Cu")
		(net "M_C_CPU1_SA_CA<0>")
	)
	(segment
		(start 64.821054 -262.83285)
		(end 64.32296 -263.330944)
		(width 0.18288)
		(layer "In4.Cu")
		(net "M_C_CPU1_SA_CA<0>")
	)
	(segment
		(start 84.434934 -256.907792)
		(end 83.576414 -256.907792)
		(width 0.18288)
		(layer "In4.Cu")
		(net "M_C_CPU1_SA_CA<0>")
	)
	(segment
		(start 43.775884 -265.669776)
		(end 40.042846 -265.669776)
		(width 0.18288)
		(layer "In4.Cu")
		(net "M_C_CPU1_SA_CA<0>")
	)
	(arc
		(start 86.562692 -256.850896)
		(mid 86.375494 -256.800753)
		(end 86.188296 -256.850896)
		(width 0.088646)
		(layer "In4.Cu")
		(net "M_C_CPU1_SA_CA<0>")
	)
	(arc
		(start 90.887296 -256.850896)
		(mid 90.604594 -256.926672)
		(end 90.321892 -256.850896)
		(width 0.088646)
		(layer "In4.Cu")
		(net "M_C_CPU1_SA_CA<0>")
	)
	(arc
		(start 87.128096 -256.850896)
		(mid 86.845394 -256.926672)
		(end 86.562692 -256.850896)
		(width 0.088646)
		(layer "In4.Cu")
		(net "M_C_CPU1_SA_CA<0>")
	)
	(arc
		(start 89.947496 -256.850896)
		(mid 89.664794 -256.926672)
		(end 89.382092 -256.850896)
		(width 0.088646)
		(layer "In4.Cu")
		(net "M_C_CPU1_SA_CA<0>")
	)
	(arc
		(start 85.622892 -256.850896)
		(mid 85.53262 -256.813297)
		(end 85.435694 -256.80035)
		(width 0.088646)
		(layer "In4.Cu")
		(net "M_C_CPU1_SA_CA<0>")
	)
	(arc
		(start 90.321892 -256.850896)
		(mid 90.134694 -256.800753)
		(end 89.947496 -256.850896)
		(width 0.088646)
		(layer "In4.Cu")
		(net "M_C_CPU1_SA_CA<0>")
	)
	(arc
		(start 87.502492 -256.850896)
		(mid 87.315294 -256.800753)
		(end 87.128096 -256.850896)
		(width 0.088646)
		(layer "In4.Cu")
		(net "M_C_CPU1_SA_CA<0>")
	)
	(arc
		(start 91.544394 -257.98907)
		(mid 91.473038 -257.58494)
		(end 91.449144 -257.175254)
		(width 0.088646)
		(layer "In4.Cu")
		(net "M_C_CPU1_SA_CA<0>")
	)
	(arc
		(start 86.188296 -256.850896)
		(mid 85.905594 -256.926672)
		(end 85.622892 -256.850896)
		(width 0.088646)
		(layer "In4.Cu")
		(net "M_C_CPU1_SA_CA<0>")
	)
	(arc
		(start 89.382092 -256.850896)
		(mid 89.194894 -256.800753)
		(end 89.007696 -256.850896)
		(width 0.088646)
		(layer "In4.Cu")
		(net "M_C_CPU1_SA_CA<0>")
	)
	(arc
		(start 88.442292 -256.850896)
		(mid 88.255094 -256.800753)
		(end 88.067896 -256.850896)
		(width 0.088646)
		(layer "In4.Cu")
		(net "M_C_CPU1_SA_CA<0>")
	)
	(arc
		(start 91.261692 -256.850896)
		(mid 91.074494 -256.800753)
		(end 90.887296 -256.850896)
		(width 0.088646)
		(layer "In4.Cu")
		(net "M_C_CPU1_SA_CA<0>")
	)
	(arc
		(start 89.007696 -256.850896)
		(mid 88.724994 -256.926672)
		(end 88.442292 -256.850896)
		(width 0.088646)
		(layer "In4.Cu")
		(net "M_C_CPU1_SA_CA<0>")
	)
	(arc
		(start 88.067896 -256.850896)
		(mid 87.785194 -256.926672)
		(end 87.502492 -256.850896)
		(width 0.088646)
		(layer "In4.Cu")
		(net "M_C_CPU1_SA_CA<0>")
	)
	(arc
		(start 91.449144 -257.175254)
		(mid 91.401465 -256.992354)
		(end 91.270582 -256.855976)
		(width 0.088646)
		(layer "In4.Cu")
		(net "M_C_CPU1_SA_CA<0>")
	)
	(segment
		(start 97.653094 -255.547368)
		(end 97.653348 -255.547622)
		(width 0.20066)
		(layer "F.Cu")
		(net "M_C_CPU1_CLK_DP<1>")
	)
	(segment
		(start 34.871914 -260.21665)
		(end 35.976814 -260.21665)
		(width 0.20066)
		(layer "F.Cu")
		(net "M_C_CPU1_CLK_DP<1>")
	)
	(segment
		(start 97.653094 -255.011682)
		(end 97.653094 -255.547368)
		(width 0.20066)
		(layer "F.Cu")
		(net "M_C_CPU1_CLK_DP<1>")
	)
	(segment
		(start 37.445696 -259.586476)
		(end 36.603686 -259.935218)
		(width 0.18288)
		(layer "In4.Cu")
		(net "M_C_CPU1_CLK_DP<1>")
	)
	(segment
		(start 97.653348 -255.547622)
		(end 97.340674 -255.547622)
		(width 0.088646)
		(layer "In4.Cu")
		(net "M_C_CPU1_CLK_DP<1>")
	)
	(segment
		(start 92.329508 -253.05893)
		(end 92.329508 -253.035562)
		(width 0.088646)
		(layer "In4.Cu")
		(net "M_C_CPU1_CLK_DP<1>")
	)
	(segment
		(start 92.672408 -254.409702)
		(end 92.671392 -254.409194)
		(width 0.088646)
		(layer "In4.Cu")
		(net "M_C_CPU1_CLK_DP<1>")
	)
	(segment
		(start 95.035878 -256.859532)
		(end 95.021146 -256.850896)
		(width 0.088646)
		(layer "In4.Cu")
		(net "M_C_CPU1_CLK_DP<1>")
	)
	(segment
		(start 79.648304 -255.16586)
		(end 67.86118 -255.16586)
		(width 0.18288)
		(layer "In4.Cu")
		(net "M_C_CPU1_CLK_DP<1>")
	)
	(segment
		(start 93.328998 -255.563116)
		(end 93.328998 -255.547622)
		(width 0.088646)
		(layer "In4.Cu")
		(net "M_C_CPU1_CLK_DP<1>")
	)
	(segment
		(start 92.389198 -253.11862)
		(end 92.329508 -253.05893)
		(width 0.088646)
		(layer "In4.Cu")
		(net "M_C_CPU1_CLK_DP<1>")
	)
	(segment
		(start 41.64711 -257.90271)
		(end 39.57574 -257.90271)
		(width 0.18288)
		(layer "In4.Cu")
		(net "M_C_CPU1_CLK_DP<1>")
	)
	(segment
		(start 96.808544 -256.361438)
		(end 96.808544 -256.376932)
		(width 0.088646)
		(layer "In4.Cu")
		(net "M_C_CPU1_CLK_DP<1>")
	)
	(segment
		(start 96.996758 -256.036572)
		(end 96.995996 -256.03708)
		(width 0.088646)
		(layer "In4.Cu")
		(net "M_C_CPU1_CLK_DP<1>")
	)
	(segment
		(start 66.399918 -256.627122)
		(end 58.419238 -256.627122)
		(width 0.18288)
		(layer "In4.Cu")
		(net "M_C_CPU1_CLK_DP<1>")
	)
	(segment
		(start 92.329508 -252.734064)
		(end 92.120974 -252.52553)
		(width 0.18288)
		(layer "In4.Cu")
		(net "M_C_CPU1_CLK_DP<1>")
	)
	(segment
		(start 92.389198 -253.93523)
		(end 92.389198 -253.11862)
		(width 0.088646)
		(layer "In4.Cu")
		(net "M_C_CPU1_CLK_DP<1>")
	)
	(segment
		(start 96.989138 -256.04089)
		(end 96.987106 -256.04216)
		(width 0.088646)
		(layer "In4.Cu")
		(net "M_C_CPU1_CLK_DP<1>")
	)
	(segment
		(start 95.975678 -256.859532)
		(end 95.960946 -256.850896)
		(width 0.088646)
		(layer "In4.Cu")
		(net "M_C_CPU1_CLK_DP<1>")
	)
	(segment
		(start 39.57574 -257.90271)
		(end 38.813994 -258.218432)
		(width 0.18288)
		(layer "In4.Cu")
		(net "M_C_CPU1_CLK_DP<1>")
	)
	(segment
		(start 97.002092 -256.033524)
		(end 96.996758 -256.036572)
		(width 0.088646)
		(layer "In4.Cu")
		(net "M_C_CPU1_CLK_DP<1>")
	)
	(segment
		(start 38.813994 -258.218432)
		(end 37.445696 -259.586476)
		(width 0.18288)
		(layer "In4.Cu")
		(net "M_C_CPU1_CLK_DP<1>")
	)
	(segment
		(start 92.120974 -252.52553)
		(end 82.288634 -252.52553)
		(width 0.18288)
		(layer "In4.Cu")
		(net "M_C_CPU1_CLK_DP<1>")
	)
	(segment
		(start 58.419238 -256.627122)
		(end 41.64711 -257.90271)
		(width 0.18288)
		(layer "In4.Cu")
		(net "M_C_CPU1_CLK_DP<1>")
	)
	(segment
		(start 67.86118 -255.16586)
		(end 66.399918 -256.627122)
		(width 0.18288)
		(layer "In4.Cu")
		(net "M_C_CPU1_CLK_DP<1>")
	)
	(segment
		(start 36.258246 -259.935218)
		(end 35.976814 -260.21665)
		(width 0.18288)
		(layer "In4.Cu")
		(net "M_C_CPU1_CLK_DP<1>")
	)
	(segment
		(start 92.329508 -253.035562)
		(end 92.329508 -252.734064)
		(width 0.18288)
		(layer "In4.Cu")
		(net "M_C_CPU1_CLK_DP<1>")
	)
	(segment
		(start 96.995996 -256.03708)
		(end 96.989138 -256.04089)
		(width 0.088646)
		(layer "In4.Cu")
		(net "M_C_CPU1_CLK_DP<1>")
	)
	(segment
		(start 97.340674 -255.547622)
		(end 97.274888 -255.613408)
		(width 0.088646)
		(layer "In4.Cu")
		(net "M_C_CPU1_CLK_DP<1>")
	)
	(segment
		(start 93.620082 -256.04216)
		(end 93.612208 -256.037588)
		(width 0.088646)
		(layer "In4.Cu")
		(net "M_C_CPU1_CLK_DP<1>")
	)
	(segment
		(start 92.858844 -254.747776)
		(end 92.858844 -254.733552)
		(width 0.088646)
		(layer "In4.Cu")
		(net "M_C_CPU1_CLK_DP<1>")
	)
	(segment
		(start 93.150436 -255.228344)
		(end 93.141546 -255.223264)
		(width 0.088646)
		(layer "In4.Cu")
		(net "M_C_CPU1_CLK_DP<1>")
	)
	(segment
		(start 94.081346 -256.850896)
		(end 94.069154 -256.843784)
		(width 0.088646)
		(layer "In4.Cu")
		(net "M_C_CPU1_CLK_DP<1>")
	)
	(segment
		(start 92.680282 -254.414274)
		(end 92.672408 -254.409702)
		(width 0.088646)
		(layer "In4.Cu")
		(net "M_C_CPU1_CLK_DP<1>")
	)
	(segment
		(start 36.603686 -259.935218)
		(end 36.258246 -259.935218)
		(width 0.18288)
		(layer "In4.Cu")
		(net "M_C_CPU1_CLK_DP<1>")
	)
	(segment
		(start 82.288634 -252.52553)
		(end 79.648304 -255.16586)
		(width 0.18288)
		(layer "In4.Cu")
		(net "M_C_CPU1_CLK_DP<1>")
	)
	(segment
		(start 93.612208 -256.037588)
		(end 93.611192 -256.03708)
		(width 0.088646)
		(layer "In4.Cu")
		(net "M_C_CPU1_CLK_DP<1>")
	)
	(arc
		(start 95.960946 -256.850896)
		(mid 95.773748 -256.800753)
		(end 95.58655 -256.850896)
		(width 0.088646)
		(layer "In4.Cu")
		(net "M_C_CPU1_CLK_DP<1>")
	)
	(arc
		(start 93.328998 -255.547622)
		(mid 93.281319 -255.364722)
		(end 93.150436 -255.228344)
		(width 0.088646)
		(layer "In4.Cu")
		(net "M_C_CPU1_CLK_DP<1>")
	)
	(arc
		(start 97.274888 -255.613408)
		(mid 97.273587 -255.623835)
		(end 97.272094 -255.634236)
		(width 0.088646)
		(layer "In4.Cu")
		(net "M_C_CPU1_CLK_DP<1>")
	)
	(arc
		(start 95.58655 -256.850896)
		(mid 95.312351 -256.926731)
		(end 95.035878 -256.859532)
		(width 0.088646)
		(layer "In4.Cu")
		(net "M_C_CPU1_CLK_DP<1>")
	)
	(arc
		(start 94.069154 -256.843784)
		(mid 93.870926 -256.637936)
		(end 93.798644 -256.361438)
		(width 0.088646)
		(layer "In4.Cu")
		(net "M_C_CPU1_CLK_DP<1>")
	)
	(arc
		(start 96.52635 -256.850896)
		(mid 96.252151 -256.926731)
		(end 95.975678 -256.859532)
		(width 0.088646)
		(layer "In4.Cu")
		(net "M_C_CPU1_CLK_DP<1>")
	)
	(arc
		(start 93.798644 -256.361438)
		(mid 93.750965 -256.178538)
		(end 93.620082 -256.04216)
		(width 0.088646)
		(layer "In4.Cu")
		(net "M_C_CPU1_CLK_DP<1>")
	)
	(arc
		(start 94.64675 -256.850896)
		(mid 94.364048 -256.926672)
		(end 94.081346 -256.850896)
		(width 0.088646)
		(layer "In4.Cu")
		(net "M_C_CPU1_CLK_DP<1>")
	)
	(arc
		(start 93.611192 -256.03708)
		(mid 93.408369 -255.836849)
		(end 93.328998 -255.563116)
		(width 0.088646)
		(layer "In4.Cu")
		(net "M_C_CPU1_CLK_DP<1>")
	)
	(arc
		(start 92.858844 -254.733552)
		(mid 92.811165 -254.550652)
		(end 92.680282 -254.414274)
		(width 0.088646)
		(layer "In4.Cu")
		(net "M_C_CPU1_CLK_DP<1>")
	)
	(arc
		(start 92.671392 -254.409194)
		(mid 92.468569 -254.208963)
		(end 92.389198 -253.93523)
		(width 0.088646)
		(layer "In4.Cu")
		(net "M_C_CPU1_CLK_DP<1>")
	)
	(arc
		(start 97.272094 -255.634236)
		(mid 97.18183 -255.864146)
		(end 97.002092 -256.033524)
		(width 0.088646)
		(layer "In4.Cu")
		(net "M_C_CPU1_CLK_DP<1>")
	)
	(arc
		(start 95.021146 -256.850896)
		(mid 94.833948 -256.800753)
		(end 94.64675 -256.850896)
		(width 0.088646)
		(layer "In4.Cu")
		(net "M_C_CPU1_CLK_DP<1>")
	)
	(arc
		(start 93.141546 -255.223264)
		(mid 92.938065 -255.02246)
		(end 92.858844 -254.747776)
		(width 0.088646)
		(layer "In4.Cu")
		(net "M_C_CPU1_CLK_DP<1>")
	)
	(arc
		(start 96.808544 -256.376932)
		(mid 96.729174 -256.650666)
		(end 96.52635 -256.850896)
		(width 0.088646)
		(layer "In4.Cu")
		(net "M_C_CPU1_CLK_DP<1>")
	)
	(arc
		(start 96.987106 -256.04216)
		(mid 96.856192 -256.17852)
		(end 96.808544 -256.361438)
		(width 0.088646)
		(layer "In4.Cu")
		(net "M_C_CPU1_CLK_DP<1>")
	)
	(segment
		(start 27.328114 -260.21665)
		(end 28.433014 -260.21665)
		(width 0.20066)
		(layer "F.Cu")
		(net "M_C_CPU1_CLK_DP<0>")
	)
	(segment
		(start 95.773494 -255.547368)
		(end 95.773748 -255.547622)
		(width 0.20066)
		(layer "F.Cu")
		(net "M_C_CPU1_CLK_DP<0>")
	)
	(segment
		(start 95.773494 -255.011682)
		(end 95.773494 -255.547368)
		(width 0.20066)
		(layer "F.Cu")
		(net "M_C_CPU1_CLK_DP<0>")
	)
	(segment
		(start 93.612208 -254.409702)
		(end 93.611192 -254.409194)
		(width 0.088646)
		(layer "In4.Cu")
		(net "M_C_CPU1_CLK_DP<0>")
	)
	(segment
		(start 93.620082 -254.414274)
		(end 93.612208 -254.409702)
		(width 0.088646)
		(layer "In4.Cu")
		(net "M_C_CPU1_CLK_DP<0>")
	)
	(segment
		(start 93.328998 -253.93523)
		(end 93.328998 -253.11862)
		(width 0.088646)
		(layer "In4.Cu")
		(net "M_C_CPU1_CLK_DP<0>")
	)
	(segment
		(start 81.958688 -251.71273)
		(end 79.338424 -254.332994)
		(width 0.18288)
		(layer "In4.Cu")
		(net "M_C_CPU1_CLK_DP<0>")
	)
	(segment
		(start 95.46082 -255.547622)
		(end 95.395288 -255.613154)
		(width 0.088646)
		(layer "In4.Cu")
		(net "M_C_CPU1_CLK_DP<0>")
	)
	(segment
		(start 93.269308 -253.035562)
		(end 93.269308 -252.413008)
		(width 0.18288)
		(layer "In4.Cu")
		(net "M_C_CPU1_CLK_DP<0>")
	)
	(segment
		(start 92.56903 -251.71273)
		(end 81.958688 -251.71273)
		(width 0.18288)
		(layer "In4.Cu")
		(net "M_C_CPU1_CLK_DP<0>")
	)
	(segment
		(start 59.963812 -255.625092)
		(end 42.790364 -256.98831)
		(width 0.18288)
		(layer "In4.Cu")
		(net "M_C_CPU1_CLK_DP<0>")
	)
	(segment
		(start 78.768956 -254.5207)
		(end 74.453242 -254.5207)
		(width 0.18288)
		(layer "In4.Cu")
		(net "M_C_CPU1_CLK_DP<0>")
	)
	(segment
		(start 94.090236 -255.228344)
		(end 94.081346 -255.223264)
		(width 0.088646)
		(layer "In4.Cu")
		(net "M_C_CPU1_CLK_DP<0>")
	)
	(segment
		(start 95.116396 -256.03708)
		(end 95.105982 -256.043176)
		(width 0.088646)
		(layer "In4.Cu")
		(net "M_C_CPU1_CLK_DP<0>")
	)
	(segment
		(start 74.18959 -254.257048)
		(end 67.407028 -254.257048)
		(width 0.18288)
		(layer "In4.Cu")
		(net "M_C_CPU1_CLK_DP<0>")
	)
	(segment
		(start 66.038984 -255.625092)
		(end 59.963812 -255.625092)
		(width 0.18288)
		(layer "In4.Cu")
		(net "M_C_CPU1_CLK_DP<0>")
	)
	(segment
		(start 74.453242 -254.5207)
		(end 74.18959 -254.257048)
		(width 0.18288)
		(layer "In4.Cu")
		(net "M_C_CPU1_CLK_DP<0>")
	)
	(segment
		(start 79.338424 -254.332994)
		(end 78.768956 -254.5207)
		(width 0.18288)
		(layer "In4.Cu")
		(net "M_C_CPU1_CLK_DP<0>")
	)
	(segment
		(start 93.269308 -253.05893)
		(end 93.269308 -253.035562)
		(width 0.088646)
		(layer "In4.Cu")
		(net "M_C_CPU1_CLK_DP<0>")
	)
	(segment
		(start 94.268798 -255.557528)
		(end 94.268798 -255.547622)
		(width 0.088646)
		(layer "In4.Cu")
		(net "M_C_CPU1_CLK_DP<0>")
	)
	(segment
		(start 93.328998 -253.11862)
		(end 93.269308 -253.05893)
		(width 0.088646)
		(layer "In4.Cu")
		(net "M_C_CPU1_CLK_DP<0>")
	)
	(segment
		(start 95.122492 -256.033524)
		(end 95.117158 -256.036572)
		(width 0.088646)
		(layer "In4.Cu")
		(net "M_C_CPU1_CLK_DP<0>")
	)
	(segment
		(start 67.407028 -254.257048)
		(end 66.038984 -255.625092)
		(width 0.18288)
		(layer "In4.Cu")
		(net "M_C_CPU1_CLK_DP<0>")
	)
	(segment
		(start 29.037534 -259.935218)
		(end 28.714446 -259.935218)
		(width 0.18288)
		(layer "In4.Cu")
		(net "M_C_CPU1_CLK_DP<0>")
	)
	(segment
		(start 42.790364 -256.98831)
		(end 33.611566 -256.98831)
		(width 0.18288)
		(layer "In4.Cu")
		(net "M_C_CPU1_CLK_DP<0>")
	)
	(segment
		(start 95.773748 -255.547622)
		(end 95.46082 -255.547622)
		(width 0.088646)
		(layer "In4.Cu")
		(net "M_C_CPU1_CLK_DP<0>")
	)
	(segment
		(start 93.798644 -254.747776)
		(end 93.798644 -254.733552)
		(width 0.088646)
		(layer "In4.Cu")
		(net "M_C_CPU1_CLK_DP<0>")
	)
	(segment
		(start 95.117158 -256.036572)
		(end 95.116396 -256.03708)
		(width 0.088646)
		(layer "In4.Cu")
		(net "M_C_CPU1_CLK_DP<0>")
	)
	(segment
		(start 29.946092 -259.558536)
		(end 29.037534 -259.935218)
		(width 0.18288)
		(layer "In4.Cu")
		(net "M_C_CPU1_CLK_DP<0>")
	)
	(segment
		(start 31.742126 -257.762502)
		(end 29.946092 -259.558536)
		(width 0.18288)
		(layer "In4.Cu")
		(net "M_C_CPU1_CLK_DP<0>")
	)
	(segment
		(start 33.611566 -256.98831)
		(end 31.742126 -257.762502)
		(width 0.18288)
		(layer "In4.Cu")
		(net "M_C_CPU1_CLK_DP<0>")
	)
	(segment
		(start 93.269308 -252.413008)
		(end 92.56903 -251.71273)
		(width 0.18288)
		(layer "In4.Cu")
		(net "M_C_CPU1_CLK_DP<0>")
	)
	(segment
		(start 28.714446 -259.935218)
		(end 28.433014 -260.21665)
		(width 0.18288)
		(layer "In4.Cu")
		(net "M_C_CPU1_CLK_DP<0>")
	)
	(arc
		(start 95.395288 -255.613154)
		(mid 95.308044 -255.855242)
		(end 95.122492 -256.033524)
		(width 0.088646)
		(layer "In4.Cu")
		(net "M_C_CPU1_CLK_DP<0>")
	)
	(arc
		(start 94.081346 -255.223264)
		(mid 93.877865 -255.02246)
		(end 93.798644 -254.747776)
		(width 0.088646)
		(layer "In4.Cu")
		(net "M_C_CPU1_CLK_DP<0>")
	)
	(arc
		(start 95.105982 -256.043176)
		(mid 94.827804 -256.112899)
		(end 94.551246 -256.03708)
		(width 0.088646)
		(layer "In4.Cu")
		(net "M_C_CPU1_CLK_DP<0>")
	)
	(arc
		(start 93.798644 -254.733552)
		(mid 93.750965 -254.550652)
		(end 93.620082 -254.414274)
		(width 0.088646)
		(layer "In4.Cu")
		(net "M_C_CPU1_CLK_DP<0>")
	)
	(arc
		(start 94.268798 -255.547622)
		(mid 94.221119 -255.364722)
		(end 94.090236 -255.228344)
		(width 0.088646)
		(layer "In4.Cu")
		(net "M_C_CPU1_CLK_DP<0>")
	)
	(arc
		(start 93.611192 -254.409194)
		(mid 93.408369 -254.208963)
		(end 93.328998 -253.93523)
		(width 0.088646)
		(layer "In4.Cu")
		(net "M_C_CPU1_CLK_DP<0>")
	)
	(arc
		(start 94.551246 -256.03708)
		(mid 94.346911 -255.834475)
		(end 94.268798 -255.557528)
		(width 0.088646)
		(layer "In4.Cu")
		(net "M_C_CPU1_CLK_DP<0>")
	)
	(segment
		(start 96.713294 -255.011682)
		(end 96.713294 -255.547368)
		(width 0.20066)
		(layer "F.Cu")
		(net "M_C_CPU1_CLK_DN<1>")
	)
	(segment
		(start 96.713294 -255.547368)
		(end 96.713548 -255.547622)
		(width 0.20066)
		(layer "F.Cu")
		(net "M_C_CPU1_CLK_DN<1>")
	)
	(segment
		(start 34.871914 -259.366766)
		(end 35.976814 -259.366766)
		(width 0.20066)
		(layer "F.Cu")
		(net "M_C_CPU1_CLK_DN<1>")
	)
	(segment
		(start 96.900746 -255.87198)
		(end 96.89465 -255.875536)
		(width 0.088646)
		(layer "In4.Cu")
		(net "M_C_CPU1_CLK_DN<1>")
	)
	(segment
		(start 79.51978 -254.85598)
		(end 67.732656 -254.85598)
		(width 0.18288)
		(layer "In4.Cu")
		(net "M_C_CPU1_CLK_DN<1>")
	)
	(segment
		(start 92.579444 -253.919482)
		(end 92.579444 -253.118874)
		(width 0.088646)
		(layer "In4.Cu")
		(net "M_C_CPU1_CLK_DN<1>")
	)
	(segment
		(start 66.271394 -256.317242)
		(end 58.4073 -256.317242)
		(width 0.18288)
		(layer "In4.Cu")
		(net "M_C_CPU1_CLK_DN<1>")
	)
	(segment
		(start 82.16011 -252.21565)
		(end 79.51978 -254.85598)
		(width 0.18288)
		(layer "In4.Cu")
		(net "M_C_CPU1_CLK_DN<1>")
	)
	(segment
		(start 93.049344 -254.733552)
		(end 93.049344 -254.718058)
		(width 0.088646)
		(layer "In4.Cu")
		(net "M_C_CPU1_CLK_DN<1>")
	)
	(segment
		(start 96.909636 -255.8669)
		(end 96.90227 -255.871218)
		(width 0.088646)
		(layer "In4.Cu")
		(net "M_C_CPU1_CLK_DN<1>")
	)
	(segment
		(start 94.17685 -256.685796)
		(end 94.16796 -256.680716)
		(width 0.088646)
		(layer "In4.Cu")
		(net "M_C_CPU1_CLK_DN<1>")
	)
	(segment
		(start 96.439482 -256.680716)
		(end 96.430592 -256.685796)
		(width 0.088646)
		(layer "In4.Cu")
		(net "M_C_CPU1_CLK_DN<1>")
	)
	(segment
		(start 92.639388 -253.035562)
		(end 92.639388 -252.60554)
		(width 0.18288)
		(layer "In4.Cu")
		(net "M_C_CPU1_CLK_DN<1>")
	)
	(segment
		(start 93.236796 -255.05791)
		(end 93.227906 -255.05283)
		(width 0.088646)
		(layer "In4.Cu")
		(net "M_C_CPU1_CLK_DN<1>")
	)
	(segment
		(start 39.514018 -257.59283)
		(end 38.638226 -257.955542)
		(width 0.18288)
		(layer "In4.Cu")
		(net "M_C_CPU1_CLK_DN<1>")
	)
	(segment
		(start 92.249498 -252.21565)
		(end 82.16011 -252.21565)
		(width 0.18288)
		(layer "In4.Cu")
		(net "M_C_CPU1_CLK_DN<1>")
	)
	(segment
		(start 92.639388 -253.05893)
		(end 92.639388 -253.035562)
		(width 0.088646)
		(layer "In4.Cu")
		(net "M_C_CPU1_CLK_DN<1>")
	)
	(segment
		(start 92.639388 -252.60554)
		(end 92.249498 -252.21565)
		(width 0.18288)
		(layer "In4.Cu")
		(net "M_C_CPU1_CLK_DN<1>")
	)
	(segment
		(start 38.638226 -257.955542)
		(end 37.269928 -259.323586)
		(width 0.18288)
		(layer "In4.Cu")
		(net "M_C_CPU1_CLK_DN<1>")
	)
	(segment
		(start 37.269928 -259.323586)
		(end 36.541964 -259.625338)
		(width 0.18288)
		(layer "In4.Cu")
		(net "M_C_CPU1_CLK_DN<1>")
	)
	(segment
		(start 36.235386 -259.625338)
		(end 35.976814 -259.366766)
		(width 0.18288)
		(layer "In4.Cu")
		(net "M_C_CPU1_CLK_DN<1>")
	)
	(segment
		(start 93.713046 -255.875536)
		(end 93.70695 -255.87198)
		(width 0.088646)
		(layer "In4.Cu")
		(net "M_C_CPU1_CLK_DN<1>")
	)
	(segment
		(start 96.056196 -256.685796)
		(end 96.041464 -256.67716)
		(width 0.088646)
		(layer "In4.Cu")
		(net "M_C_CPU1_CLK_DN<1>")
	)
	(segment
		(start 41.635172 -257.59283)
		(end 39.514018 -257.59283)
		(width 0.18288)
		(layer "In4.Cu")
		(net "M_C_CPU1_CLK_DN<1>")
	)
	(segment
		(start 96.713548 -255.547622)
		(end 97.026222 -255.547622)
		(width 0.088646)
		(layer "In4.Cu")
		(net "M_C_CPU1_CLK_DN<1>")
	)
	(segment
		(start 93.519498 -255.547622)
		(end 93.519498 -255.533398)
		(width 0.088646)
		(layer "In4.Cu")
		(net "M_C_CPU1_CLK_DN<1>")
	)
	(segment
		(start 92.76715 -254.244094)
		(end 92.75826 -254.239014)
		(width 0.088646)
		(layer "In4.Cu")
		(net "M_C_CPU1_CLK_DN<1>")
	)
	(segment
		(start 58.4073 -256.317242)
		(end 41.635172 -257.59283)
		(width 0.18288)
		(layer "In4.Cu")
		(net "M_C_CPU1_CLK_DN<1>")
	)
	(segment
		(start 36.541964 -259.625338)
		(end 36.235386 -259.625338)
		(width 0.18288)
		(layer "In4.Cu")
		(net "M_C_CPU1_CLK_DN<1>")
	)
	(segment
		(start 97.026222 -255.547622)
		(end 97.083626 -255.605026)
		(width 0.088646)
		(layer "In4.Cu")
		(net "M_C_CPU1_CLK_DN<1>")
	)
	(segment
		(start 95.116396 -256.685796)
		(end 95.105982 -256.6797)
		(width 0.088646)
		(layer "In4.Cu")
		(net "M_C_CPU1_CLK_DN<1>")
	)
	(segment
		(start 67.732656 -254.85598)
		(end 66.271394 -256.317242)
		(width 0.18288)
		(layer "In4.Cu")
		(net "M_C_CPU1_CLK_DN<1>")
	)
	(segment
		(start 93.70695 -255.87198)
		(end 93.69806 -255.8669)
		(width 0.088646)
		(layer "In4.Cu")
		(net "M_C_CPU1_CLK_DN<1>")
	)
	(segment
		(start 92.579698 -253.919736)
		(end 92.579444 -253.919482)
		(width 0.088646)
		(layer "In4.Cu")
		(net "M_C_CPU1_CLK_DN<1>")
	)
	(segment
		(start 96.90227 -255.871218)
		(end 96.900746 -255.87198)
		(width 0.088646)
		(layer "In4.Cu")
		(net "M_C_CPU1_CLK_DN<1>")
	)
	(segment
		(start 92.579444 -253.118874)
		(end 92.639388 -253.05893)
		(width 0.088646)
		(layer "In4.Cu")
		(net "M_C_CPU1_CLK_DN<1>")
	)
	(arc
		(start 93.049344 -254.718058)
		(mid 92.969974 -254.444324)
		(end 92.76715 -254.244094)
		(width 0.088646)
		(layer "In4.Cu")
		(net "M_C_CPU1_CLK_DN<1>")
	)
	(arc
		(start 93.989398 -256.361438)
		(mid 93.915482 -256.081936)
		(end 93.713046 -255.875536)
		(width 0.088646)
		(layer "In4.Cu")
		(net "M_C_CPU1_CLK_DN<1>")
	)
	(arc
		(start 97.083626 -255.605026)
		(mid 97.02547 -255.755139)
		(end 96.909636 -255.8669)
		(width 0.088646)
		(layer "In4.Cu")
		(net "M_C_CPU1_CLK_DN<1>")
	)
	(arc
		(start 95.105982 -256.6797)
		(mid 94.827804 -256.609977)
		(end 94.551246 -256.685796)
		(width 0.088646)
		(layer "In4.Cu")
		(net "M_C_CPU1_CLK_DN<1>")
	)
	(arc
		(start 92.75826 -254.239014)
		(mid 92.627346 -254.102654)
		(end 92.579698 -253.919736)
		(width 0.088646)
		(layer "In4.Cu")
		(net "M_C_CPU1_CLK_DN<1>")
	)
	(arc
		(start 96.041464 -256.67716)
		(mid 95.764989 -256.60984)
		(end 95.490792 -256.685796)
		(width 0.088646)
		(layer "In4.Cu")
		(net "M_C_CPU1_CLK_DN<1>")
	)
	(arc
		(start 96.618044 -256.361438)
		(mid 96.570365 -256.544338)
		(end 96.439482 -256.680716)
		(width 0.088646)
		(layer "In4.Cu")
		(net "M_C_CPU1_CLK_DN<1>")
	)
	(arc
		(start 96.430592 -256.685796)
		(mid 96.243394 -256.735939)
		(end 96.056196 -256.685796)
		(width 0.088646)
		(layer "In4.Cu")
		(net "M_C_CPU1_CLK_DN<1>")
	)
	(arc
		(start 93.69806 -255.8669)
		(mid 93.567146 -255.73054)
		(end 93.519498 -255.547622)
		(width 0.088646)
		(layer "In4.Cu")
		(net "M_C_CPU1_CLK_DN<1>")
	)
	(arc
		(start 96.89465 -255.875536)
		(mid 96.692063 -256.081887)
		(end 96.618044 -256.361438)
		(width 0.088646)
		(layer "In4.Cu")
		(net "M_C_CPU1_CLK_DN<1>")
	)
	(arc
		(start 94.16796 -256.680716)
		(mid 94.037046 -256.544356)
		(end 93.989398 -256.361438)
		(width 0.088646)
		(layer "In4.Cu")
		(net "M_C_CPU1_CLK_DN<1>")
	)
	(arc
		(start 93.519498 -255.533398)
		(mid 93.440279 -255.258713)
		(end 93.236796 -255.05791)
		(width 0.088646)
		(layer "In4.Cu")
		(net "M_C_CPU1_CLK_DN<1>")
	)
	(arc
		(start 93.227906 -255.05283)
		(mid 93.096992 -254.91647)
		(end 93.049344 -254.733552)
		(width 0.088646)
		(layer "In4.Cu")
		(net "M_C_CPU1_CLK_DN<1>")
	)
	(arc
		(start 95.490792 -256.685796)
		(mid 95.303594 -256.735939)
		(end 95.116396 -256.685796)
		(width 0.088646)
		(layer "In4.Cu")
		(net "M_C_CPU1_CLK_DN<1>")
	)
	(arc
		(start 94.551246 -256.685796)
		(mid 94.364048 -256.735939)
		(end 94.17685 -256.685796)
		(width 0.088646)
		(layer "In4.Cu")
		(net "M_C_CPU1_CLK_DN<1>")
	)
	(segment
		(start 94.833694 -255.547368)
		(end 94.833948 -255.547622)
		(width 0.20066)
		(layer "F.Cu")
		(net "M_C_CPU1_CLK_DN<0>")
	)
	(segment
		(start 27.328114 -259.366766)
		(end 28.433014 -259.366766)
		(width 0.20066)
		(layer "F.Cu")
		(net "M_C_CPU1_CLK_DN<0>")
	)
	(segment
		(start 94.833694 -255.011682)
		(end 94.833694 -255.547368)
		(width 0.20066)
		(layer "F.Cu")
		(net "M_C_CPU1_CLK_DN<0>")
	)
	(segment
		(start 28.691586 -259.625338)
		(end 28.433014 -259.366766)
		(width 0.18288)
		(layer "In4.Cu")
		(net "M_C_CPU1_CLK_DN<0>")
	)
	(segment
		(start 93.519244 -253.919482)
		(end 93.519244 -253.118874)
		(width 0.088646)
		(layer "In4.Cu")
		(net "M_C_CPU1_CLK_DN<0>")
	)
	(segment
		(start 67.278504 -253.947168)
		(end 65.91046 -255.315212)
		(width 0.18288)
		(layer "In4.Cu")
		(net "M_C_CPU1_CLK_DN<0>")
	)
	(segment
		(start 74.581766 -254.21082)
		(end 74.318114 -253.947168)
		(width 0.18288)
		(layer "In4.Cu")
		(net "M_C_CPU1_CLK_DN<0>")
	)
	(segment
		(start 94.176596 -255.05791)
		(end 94.167706 -255.05283)
		(width 0.088646)
		(layer "In4.Cu")
		(net "M_C_CPU1_CLK_DN<0>")
	)
	(segment
		(start 93.579188 -252.284484)
		(end 92.697554 -251.40285)
		(width 0.18288)
		(layer "In4.Cu")
		(net "M_C_CPU1_CLK_DN<0>")
	)
	(segment
		(start 92.697554 -251.40285)
		(end 81.830164 -251.40285)
		(width 0.18288)
		(layer "In4.Cu")
		(net "M_C_CPU1_CLK_DN<0>")
	)
	(segment
		(start 94.833948 -255.547622)
		(end 95.146876 -255.547622)
		(width 0.088646)
		(layer "In4.Cu")
		(net "M_C_CPU1_CLK_DN<0>")
	)
	(segment
		(start 79.171292 -254.061722)
		(end 78.719172 -254.21082)
		(width 0.18288)
		(layer "In4.Cu")
		(net "M_C_CPU1_CLK_DN<0>")
	)
	(segment
		(start 59.951366 -255.315212)
		(end 42.777918 -256.678176)
		(width 0.18288)
		(layer "In4.Cu")
		(net "M_C_CPU1_CLK_DN<0>")
	)
	(segment
		(start 95.030036 -255.8669)
		(end 95.02267 -255.871218)
		(width 0.088646)
		(layer "In4.Cu")
		(net "M_C_CPU1_CLK_DN<0>")
	)
	(segment
		(start 93.579188 -253.05893)
		(end 93.579188 -253.035562)
		(width 0.088646)
		(layer "In4.Cu")
		(net "M_C_CPU1_CLK_DN<0>")
	)
	(segment
		(start 93.519244 -253.118874)
		(end 93.579188 -253.05893)
		(width 0.088646)
		(layer "In4.Cu")
		(net "M_C_CPU1_CLK_DN<0>")
	)
	(segment
		(start 93.989144 -254.733552)
		(end 93.989144 -254.718058)
		(width 0.088646)
		(layer "In4.Cu")
		(net "M_C_CPU1_CLK_DN<0>")
	)
	(segment
		(start 33.549844 -256.67843)
		(end 31.566358 -257.499612)
		(width 0.18288)
		(layer "In4.Cu")
		(net "M_C_CPU1_CLK_DN<0>")
	)
	(segment
		(start 31.566358 -257.499612)
		(end 29.770324 -259.295646)
		(width 0.18288)
		(layer "In4.Cu")
		(net "M_C_CPU1_CLK_DN<0>")
	)
	(segment
		(start 94.64675 -255.87198)
		(end 94.63786 -255.8669)
		(width 0.088646)
		(layer "In4.Cu")
		(net "M_C_CPU1_CLK_DN<0>")
	)
	(segment
		(start 94.459298 -255.547622)
		(end 94.459298 -255.533398)
		(width 0.088646)
		(layer "In4.Cu")
		(net "M_C_CPU1_CLK_DN<0>")
	)
	(segment
		(start 95.146876 -255.547622)
		(end 95.204026 -255.604772)
		(width 0.088646)
		(layer "In4.Cu")
		(net "M_C_CPU1_CLK_DN<0>")
	)
	(segment
		(start 29.770324 -259.295646)
		(end 28.975812 -259.625338)
		(width 0.18288)
		(layer "In4.Cu")
		(net "M_C_CPU1_CLK_DN<0>")
	)
	(segment
		(start 42.777918 -256.678176)
		(end 42.777664 -256.67843)
		(width 0.18288)
		(layer "In4.Cu")
		(net "M_C_CPU1_CLK_DN<0>")
	)
	(segment
		(start 42.777664 -256.67843)
		(end 33.549844 -256.67843)
		(width 0.18288)
		(layer "In4.Cu")
		(net "M_C_CPU1_CLK_DN<0>")
	)
	(segment
		(start 65.91046 -255.315212)
		(end 59.951366 -255.315212)
		(width 0.18288)
		(layer "In4.Cu")
		(net "M_C_CPU1_CLK_DN<0>")
	)
	(segment
		(start 74.318114 -253.947168)
		(end 67.278504 -253.947168)
		(width 0.18288)
		(layer "In4.Cu")
		(net "M_C_CPU1_CLK_DN<0>")
	)
	(segment
		(start 28.975812 -259.625338)
		(end 28.691586 -259.625338)
		(width 0.18288)
		(layer "In4.Cu")
		(net "M_C_CPU1_CLK_DN<0>")
	)
	(segment
		(start 93.579188 -253.035562)
		(end 93.579188 -252.284484)
		(width 0.18288)
		(layer "In4.Cu")
		(net "M_C_CPU1_CLK_DN<0>")
	)
	(segment
		(start 93.519498 -253.919736)
		(end 93.519244 -253.919482)
		(width 0.088646)
		(layer "In4.Cu")
		(net "M_C_CPU1_CLK_DN<0>")
	)
	(segment
		(start 95.02267 -255.871218)
		(end 95.021146 -255.87198)
		(width 0.088646)
		(layer "In4.Cu")
		(net "M_C_CPU1_CLK_DN<0>")
	)
	(segment
		(start 78.719172 -254.21082)
		(end 74.581766 -254.21082)
		(width 0.18288)
		(layer "In4.Cu")
		(net "M_C_CPU1_CLK_DN<0>")
	)
	(segment
		(start 93.70695 -254.244094)
		(end 93.69806 -254.239014)
		(width 0.088646)
		(layer "In4.Cu")
		(net "M_C_CPU1_CLK_DN<0>")
	)
	(segment
		(start 81.830164 -251.40285)
		(end 79.171292 -254.061722)
		(width 0.18288)
		(layer "In4.Cu")
		(net "M_C_CPU1_CLK_DN<0>")
	)
	(arc
		(start 94.459298 -255.533398)
		(mid 94.380079 -255.258713)
		(end 94.176596 -255.05791)
		(width 0.088646)
		(layer "In4.Cu")
		(net "M_C_CPU1_CLK_DN<0>")
	)
	(arc
		(start 94.63786 -255.8669)
		(mid 94.506946 -255.73054)
		(end 94.459298 -255.547622)
		(width 0.088646)
		(layer "In4.Cu")
		(net "M_C_CPU1_CLK_DN<0>")
	)
	(arc
		(start 93.69806 -254.239014)
		(mid 93.567146 -254.102654)
		(end 93.519498 -253.919736)
		(width 0.088646)
		(layer "In4.Cu")
		(net "M_C_CPU1_CLK_DN<0>")
	)
	(arc
		(start 95.021146 -255.87198)
		(mid 94.833948 -255.922123)
		(end 94.64675 -255.87198)
		(width 0.088646)
		(layer "In4.Cu")
		(net "M_C_CPU1_CLK_DN<0>")
	)
	(arc
		(start 93.989144 -254.718058)
		(mid 93.909774 -254.444324)
		(end 93.70695 -254.244094)
		(width 0.088646)
		(layer "In4.Cu")
		(net "M_C_CPU1_CLK_DN<0>")
	)
	(arc
		(start 95.204026 -255.604772)
		(mid 95.145907 -255.755013)
		(end 95.030036 -255.8669)
		(width 0.088646)
		(layer "In4.Cu")
		(net "M_C_CPU1_CLK_DN<0>")
	)
	(arc
		(start 94.167706 -255.05283)
		(mid 94.036792 -254.91647)
		(end 93.989144 -254.733552)
		(width 0.088646)
		(layer "In4.Cu")
		(net "M_C_CPU1_CLK_DN<0>")
	)
	(segment
		(start 24.773636 -269.777972)
		(end 25.27808 -269.777972)
		(width 0.20066)
		(layer "F.Cu")
		(net "M_C_CPU1_ALERT_N")
	)
	(segment
		(start 25.27808 -269.777972)
		(end 25.432512 -269.62354)
		(width 0.20066)
		(layer "F.Cu")
		(net "M_C_CPU1_ALERT_N")
	)
	(segment
		(start 25.595072 -269.132812)
		(end 26.20391 -269.132812)
		(width 0.20066)
		(layer "F.Cu")
		(net "M_C_CPU1_ALERT_N")
	)
	(segment
		(start 26.2128 -269.141702)
		(end 28.198318 -269.141702)
		(width 0.1016)
		(layer "F.Cu")
		(net "M_C_CPU1_ALERT_N")
	)
	(segment
		(start 28.198318 -269.141702)
		(end 28.529026 -269.141702)
		(width 0.101854)
		(layer "F.Cu")
		(net "M_C_CPU1_ALERT_N")
	)
	(segment
		(start 29.13253 -269.566644)
		(end 30.771846 -269.566644)
		(width 0.20066)
		(layer "F.Cu")
		(net "M_C_CPU1_ALERT_N")
	)
	(segment
		(start 28.707588 -269.141702)
		(end 29.13253 -269.566644)
		(width 0.20066)
		(layer "F.Cu")
		(net "M_C_CPU1_ALERT_N")
	)
	(segment
		(start 101.412294 -253.383796)
		(end 101.412294 -253.919482)
		(width 0.20066)
		(layer "F.Cu")
		(net "M_C_CPU1_ALERT_N")
	)
	(segment
		(start 24.562308 -269.566644)
		(end 24.773636 -269.777972)
		(width 0.20066)
		(layer "F.Cu")
		(net "M_C_CPU1_ALERT_N")
	)
	(segment
		(start 25.432512 -269.62354)
		(end 25.432512 -269.295372)
		(width 0.20066)
		(layer "F.Cu")
		(net "M_C_CPU1_ALERT_N")
	)
	(segment
		(start 26.20391 -269.132812)
		(end 26.2128 -269.141702)
		(width 0.1016)
		(layer "F.Cu")
		(net "M_C_CPU1_ALERT_N")
	)
	(segment
		(start 25.432512 -269.295372)
		(end 25.595072 -269.132812)
		(width 0.20066)
		(layer "F.Cu")
		(net "M_C_CPU1_ALERT_N")
	)
	(segment
		(start 28.529026 -269.141702)
		(end 28.707588 -269.141702)
		(width 0.20066)
		(layer "F.Cu")
		(net "M_C_CPU1_ALERT_N")
	)
	(segment
		(start 31.876746 -269.566644)
		(end 30.771846 -269.566644)
		(width 0.20066)
		(layer "F.Cu")
		(net "M_C_CPU1_ALERT_N")
	)
	(segment
		(start 23.228046 -269.566644)
		(end 24.562308 -269.566644)
		(width 0.20066)
		(layer "F.Cu")
		(net "M_C_CPU1_ALERT_N")
	)
	(segment
		(start 101.412294 -253.919482)
		(end 101.412548 -253.919736)
		(width 0.20066)
		(layer "F.Cu")
		(net "M_C_CPU1_ALERT_N")
	)
	(via
		(at 31.876746 -269.566644)
		(size 0.4572)
		(drill 0.2032)
		(layers "F.Cu" "B.Cu")
		(net "M_C_CPU1_ALERT_N")
	)
	(via
		(at 101.412548 -253.919736)
		(size 0.4572)
		(drill 0.2032)
		(layers "F.Cu" "B.Cu")
		(net "M_C_CPU1_ALERT_N")
	)
	(segment
		(start 51.75758 -260.38048)
		(end 51.49723 -260.64083)
		(width 0.18288)
		(layer "In6.Cu")
		(net "M_C_CPU1_ALERT_N")
	)
	(segment
		(start 84.265008 -257.582162)
		(end 83.932776 -257.582162)
		(width 0.18288)
		(layer "In6.Cu")
		(net "M_C_CPU1_ALERT_N")
	)
	(segment
		(start 36.57727 -265.135614)
		(end 36.57727 -267.184378)
		(width 0.18288)
		(layer "In6.Cu")
		(net "M_C_CPU1_ALERT_N")
	)
	(segment
		(start 60.183776 -259.484622)
		(end 52.171092 -259.484622)
		(width 0.18288)
		(layer "In6.Cu")
		(net "M_C_CPU1_ALERT_N")
	)
	(segment
		(start 99.30257 -256.765552)
		(end 99.297744 -256.768346)
		(width 0.18288)
		(layer "In6.Cu")
		(net "M_C_CPU1_ALERT_N")
	)
	(segment
		(start 99.063048 -257.160776)
		(end 99.063048 -257.175254)
		(width 0.18288)
		(layer "In6.Cu")
		(net "M_C_CPU1_ALERT_N")
	)
	(segment
		(start 77.667104 -259.08635)
		(end 66.475356 -259.08635)
		(width 0.18288)
		(layer "In6.Cu")
		(net "M_C_CPU1_ALERT_N")
	)
	(segment
		(start 96.948498 -257.582162)
		(end 96.938846 -257.58775)
		(width 0.18288)
		(layer "In6.Cu")
		(net "M_C_CPU1_ALERT_N")
	)
	(segment
		(start 40.202358 -262.958326)
		(end 38.754558 -262.958326)
		(width 0.18288)
		(layer "In6.Cu")
		(net "M_C_CPU1_ALERT_N")
	)
	(segment
		(start 80.81264 -257.783584)
		(end 77.667104 -259.08635)
		(width 0.18288)
		(layer "In6.Cu")
		(net "M_C_CPU1_ALERT_N")
	)
	(segment
		(start 85.709506 -257.56108)
		(end 85.672676 -257.582162)
		(width 0.18288)
		(layer "In6.Cu")
		(net "M_C_CPU1_ALERT_N")
	)
	(segment
		(start 83.731354 -257.783584)
		(end 80.81264 -257.783584)
		(width 0.18288)
		(layer "In6.Cu")
		(net "M_C_CPU1_ALERT_N")
	)
	(segment
		(start 38.754558 -262.958326)
		(end 36.57727 -265.135614)
		(width 0.18288)
		(layer "In6.Cu")
		(net "M_C_CPU1_ALERT_N")
	)
	(segment
		(start 51.75758 -259.898134)
		(end 51.75758 -260.38048)
		(width 0.18288)
		(layer "In6.Cu")
		(net "M_C_CPU1_ALERT_N")
	)
	(segment
		(start 83.932776 -257.582162)
		(end 83.731354 -257.783584)
		(width 0.18288)
		(layer "In6.Cu")
		(net "M_C_CPU1_ALERT_N")
	)
	(segment
		(start 100.707444 -254.326644)
		(end 100.702618 -254.329438)
		(width 0.18288)
		(layer "In6.Cu")
		(net "M_C_CPU1_ALERT_N")
	)
	(segment
		(start 99.767644 -255.95453)
		(end 99.762818 -255.957324)
		(width 0.18288)
		(layer "In6.Cu")
		(net "M_C_CPU1_ALERT_N")
	)
	(segment
		(start 90.839544 -257.582162)
		(end 90.826082 -257.574288)
		(width 0.18288)
		(layer "In6.Cu")
		(net "M_C_CPU1_ALERT_N")
	)
	(segment
		(start 34.961576 -267.440918)
		(end 32.83585 -269.566644)
		(width 0.18288)
		(layer "In6.Cu")
		(net "M_C_CPU1_ALERT_N")
	)
	(segment
		(start 66.475102 -259.086604)
		(end 60.581794 -259.086604)
		(width 0.18288)
		(layer "In6.Cu")
		(net "M_C_CPU1_ALERT_N")
	)
	(segment
		(start 100.002848 -255.53797)
		(end 100.002848 -255.547622)
		(width 0.18288)
		(layer "In6.Cu")
		(net "M_C_CPU1_ALERT_N")
	)
	(segment
		(start 100.472494 -254.733552)
		(end 100.472494 -254.747014)
		(width 0.18288)
		(layer "In6.Cu")
		(net "M_C_CPU1_ALERT_N")
	)
	(segment
		(start 45.20311 -260.64083)
		(end 44.148502 -261.695438)
		(width 0.18288)
		(layer "In6.Cu")
		(net "M_C_CPU1_ALERT_N")
	)
	(segment
		(start 99.778312 -255.94818)
		(end 99.767644 -255.95453)
		(width 0.18288)
		(layer "In6.Cu")
		(net "M_C_CPU1_ALERT_N")
	)
	(segment
		(start 85.672676 -257.582162)
		(end 85.64753 -257.59664)
		(width 0.18288)
		(layer "In6.Cu")
		(net "M_C_CPU1_ALERT_N")
	)
	(segment
		(start 66.475356 -259.08635)
		(end 66.475102 -259.086604)
		(width 0.18288)
		(layer "In6.Cu")
		(net "M_C_CPU1_ALERT_N")
	)
	(segment
		(start 86.612222 -257.582162)
		(end 86.576662 -257.602736)
		(width 0.18288)
		(layer "In6.Cu")
		(net "M_C_CPU1_ALERT_N")
	)
	(segment
		(start 101.412548 -253.919736)
		(end 100.707698 -254.326644)
		(width 0.18288)
		(layer "In6.Cu")
		(net "M_C_CPU1_ALERT_N")
	)
	(segment
		(start 92.719144 -257.582162)
		(end 92.709492 -257.576574)
		(width 0.18288)
		(layer "In6.Cu")
		(net "M_C_CPU1_ALERT_N")
	)
	(segment
		(start 87.575136 -257.5687)
		(end 87.551768 -257.582162)
		(width 0.18288)
		(layer "In6.Cu")
		(net "M_C_CPU1_ALERT_N")
	)
	(segment
		(start 87.551768 -257.582162)
		(end 87.516208 -257.602736)
		(width 0.18288)
		(layer "In6.Cu")
		(net "M_C_CPU1_ALERT_N")
	)
	(segment
		(start 84.74456 -257.576574)
		(end 84.734908 -257.582162)
		(width 0.18288)
		(layer "In6.Cu")
		(net "M_C_CPU1_ALERT_N")
	)
	(segment
		(start 44.148502 -261.695438)
		(end 41.465246 -261.695438)
		(width 0.18288)
		(layer "In6.Cu")
		(net "M_C_CPU1_ALERT_N")
	)
	(segment
		(start 96.008444 -257.582162)
		(end 95.994982 -257.590036)
		(width 0.18288)
		(layer "In6.Cu")
		(net "M_C_CPU1_ALERT_N")
	)
	(segment
		(start 95.068644 -257.582162)
		(end 95.055182 -257.590036)
		(width 0.18288)
		(layer "In6.Cu")
		(net "M_C_CPU1_ALERT_N")
	)
	(segment
		(start 97.418144 -257.582162)
		(end 97.408492 -257.576574)
		(width 0.18288)
		(layer "In6.Cu")
		(net "M_C_CPU1_ALERT_N")
	)
	(segment
		(start 86.646512 -257.56235)
		(end 86.612222 -257.582162)
		(width 0.18288)
		(layer "In6.Cu")
		(net "M_C_CPU1_ALERT_N")
	)
	(segment
		(start 51.49723 -260.64083)
		(end 45.20311 -260.64083)
		(width 0.18288)
		(layer "In6.Cu")
		(net "M_C_CPU1_ALERT_N")
	)
	(segment
		(start 98.832924 -257.579368)
		(end 98.818446 -257.58775)
		(width 0.18288)
		(layer "In6.Cu")
		(net "M_C_CPU1_ALERT_N")
	)
	(segment
		(start 36.57727 -267.184378)
		(end 36.32073 -267.440918)
		(width 0.18288)
		(layer "In6.Cu")
		(net "M_C_CPU1_ALERT_N")
	)
	(segment
		(start 32.83585 -269.566644)
		(end 31.876746 -269.566644)
		(width 0.18288)
		(layer "In6.Cu")
		(net "M_C_CPU1_ALERT_N")
	)
	(segment
		(start 60.581794 -259.086604)
		(end 60.183776 -259.484622)
		(width 0.18288)
		(layer "In6.Cu")
		(net "M_C_CPU1_ALERT_N")
	)
	(segment
		(start 36.32073 -267.440918)
		(end 34.961576 -267.440918)
		(width 0.18288)
		(layer "In6.Cu")
		(net "M_C_CPU1_ALERT_N")
	)
	(segment
		(start 41.465246 -261.695438)
		(end 40.202358 -262.958326)
		(width 0.18288)
		(layer "In6.Cu")
		(net "M_C_CPU1_ALERT_N")
	)
	(segment
		(start 94.128844 -257.582162)
		(end 94.115382 -257.590036)
		(width 0.18288)
		(layer "In6.Cu")
		(net "M_C_CPU1_ALERT_N")
	)
	(segment
		(start 100.707698 -254.326644)
		(end 100.707444 -254.326644)
		(width 0.18288)
		(layer "In6.Cu")
		(net "M_C_CPU1_ALERT_N")
	)
	(segment
		(start 92.249498 -257.582162)
		(end 92.239846 -257.58775)
		(width 0.18288)
		(layer "In6.Cu")
		(net "M_C_CPU1_ALERT_N")
	)
	(segment
		(start 52.171092 -259.484622)
		(end 51.75758 -259.898134)
		(width 0.18288)
		(layer "In6.Cu")
		(net "M_C_CPU1_ALERT_N")
	)
	(arc
		(start 97.408492 -257.576574)
		(mid 97.177761 -257.519213)
		(end 96.948498 -257.582162)
		(width 0.18288)
		(layer "In6.Cu")
		(net "M_C_CPU1_ALERT_N")
	)
	(arc
		(start 98.357944 -257.582162)
		(mid 98.122994 -257.519202)
		(end 97.888044 -257.582162)
		(width 0.18288)
		(layer "In6.Cu")
		(net "M_C_CPU1_ALERT_N")
	)
	(arc
		(start 91.779344 -257.582162)
		(mid 91.544394 -257.519202)
		(end 91.309444 -257.582162)
		(width 0.18288)
		(layer "In6.Cu")
		(net "M_C_CPU1_ALERT_N")
	)
	(arc
		(start 95.994982 -257.590036)
		(mid 95.765729 -257.64528)
		(end 95.538544 -257.582162)
		(width 0.18288)
		(layer "In6.Cu")
		(net "M_C_CPU1_ALERT_N")
	)
	(arc
		(start 88.959944 -257.582162)
		(mid 88.724994 -257.519202)
		(end 88.490044 -257.582162)
		(width 0.18288)
		(layer "In6.Cu")
		(net "M_C_CPU1_ALERT_N")
	)
	(arc
		(start 86.576662 -257.602736)
		(mid 86.356982 -257.645565)
		(end 86.142322 -257.582162)
		(width 0.18288)
		(layer "In6.Cu")
		(net "M_C_CPU1_ALERT_N")
	)
	(arc
		(start 88.490044 -257.582162)
		(mid 88.255094 -257.645122)
		(end 88.020144 -257.582162)
		(width 0.18288)
		(layer "In6.Cu")
		(net "M_C_CPU1_ALERT_N")
	)
	(arc
		(start 85.204554 -257.582162)
		(mid 84.975291 -257.519237)
		(end 84.74456 -257.576574)
		(width 0.18288)
		(layer "In6.Cu")
		(net "M_C_CPU1_ALERT_N")
	)
	(arc
		(start 96.478344 -257.582162)
		(mid 96.243394 -257.519202)
		(end 96.008444 -257.582162)
		(width 0.18288)
		(layer "In6.Cu")
		(net "M_C_CPU1_ALERT_N")
	)
	(arc
		(start 90.369644 -257.582162)
		(mid 90.134694 -257.645122)
		(end 89.899744 -257.582162)
		(width 0.18288)
		(layer "In6.Cu")
		(net "M_C_CPU1_ALERT_N")
	)
	(arc
		(start 97.888044 -257.582162)
		(mid 97.653094 -257.645122)
		(end 97.418144 -257.582162)
		(width 0.18288)
		(layer "In6.Cu")
		(net "M_C_CPU1_ALERT_N")
	)
	(arc
		(start 100.002848 -255.547622)
		(mid 99.942893 -255.777232)
		(end 99.778312 -255.94818)
		(width 0.18288)
		(layer "In6.Cu")
		(net "M_C_CPU1_ALERT_N")
	)
	(arc
		(start 87.081868 -257.582162)
		(mid 86.866613 -257.518801)
		(end 86.646512 -257.56235)
		(width 0.18288)
		(layer "In6.Cu")
		(net "M_C_CPU1_ALERT_N")
	)
	(arc
		(start 92.239846 -257.58775)
		(mid 92.008861 -257.645233)
		(end 91.779344 -257.582162)
		(width 0.18288)
		(layer "In6.Cu")
		(net "M_C_CPU1_ALERT_N")
	)
	(arc
		(start 90.826082 -257.574288)
		(mid 90.596829 -257.519044)
		(end 90.369644 -257.582162)
		(width 0.18288)
		(layer "In6.Cu")
		(net "M_C_CPU1_ALERT_N")
	)
	(arc
		(start 96.938846 -257.58775)
		(mid 96.707861 -257.645233)
		(end 96.478344 -257.582162)
		(width 0.18288)
		(layer "In6.Cu")
		(net "M_C_CPU1_ALERT_N")
	)
	(arc
		(start 89.429844 -257.582162)
		(mid 89.194894 -257.645122)
		(end 88.959944 -257.582162)
		(width 0.18288)
		(layer "In6.Cu")
		(net "M_C_CPU1_ALERT_N")
	)
	(arc
		(start 93.658944 -257.582162)
		(mid 93.423994 -257.519202)
		(end 93.189044 -257.582162)
		(width 0.18288)
		(layer "In6.Cu")
		(net "M_C_CPU1_ALERT_N")
	)
	(arc
		(start 94.598744 -257.582162)
		(mid 94.363794 -257.519202)
		(end 94.128844 -257.582162)
		(width 0.18288)
		(layer "In6.Cu")
		(net "M_C_CPU1_ALERT_N")
	)
	(arc
		(start 98.818446 -257.58775)
		(mid 98.587461 -257.645233)
		(end 98.357944 -257.582162)
		(width 0.18288)
		(layer "In6.Cu")
		(net "M_C_CPU1_ALERT_N")
	)
	(arc
		(start 92.709492 -257.576574)
		(mid 92.478761 -257.519213)
		(end 92.249498 -257.582162)
		(width 0.18288)
		(layer "In6.Cu")
		(net "M_C_CPU1_ALERT_N")
	)
	(arc
		(start 87.516208 -257.602736)
		(mid 87.296528 -257.645565)
		(end 87.081868 -257.582162)
		(width 0.18288)
		(layer "In6.Cu")
		(net "M_C_CPU1_ALERT_N")
	)
	(arc
		(start 99.762818 -255.957324)
		(mid 99.594262 -256.128918)
		(end 99.532694 -256.361438)
		(width 0.18288)
		(layer "In6.Cu")
		(net "M_C_CPU1_ALERT_N")
	)
	(arc
		(start 84.734908 -257.582162)
		(mid 84.499958 -257.645122)
		(end 84.265008 -257.582162)
		(width 0.18288)
		(layer "In6.Cu")
		(net "M_C_CPU1_ALERT_N")
	)
	(arc
		(start 86.142322 -257.582162)
		(mid 85.928485 -257.518868)
		(end 85.709506 -257.56108)
		(width 0.18288)
		(layer "In6.Cu")
		(net "M_C_CPU1_ALERT_N")
	)
	(arc
		(start 100.237544 -255.140714)
		(mid 100.068094 -255.30856)
		(end 100.002848 -255.53797)
		(width 0.18288)
		(layer "In6.Cu")
		(net "M_C_CPU1_ALERT_N")
	)
	(arc
		(start 99.532694 -256.361438)
		(mid 99.471131 -256.593961)
		(end 99.30257 -256.765552)
		(width 0.18288)
		(layer "In6.Cu")
		(net "M_C_CPU1_ALERT_N")
	)
	(arc
		(start 85.64753 -257.59664)
		(mid 85.424218 -257.644943)
		(end 85.204554 -257.582162)
		(width 0.18288)
		(layer "In6.Cu")
		(net "M_C_CPU1_ALERT_N")
	)
	(arc
		(start 95.055182 -257.590036)
		(mid 94.825929 -257.64528)
		(end 94.598744 -257.582162)
		(width 0.18288)
		(layer "In6.Cu")
		(net "M_C_CPU1_ALERT_N")
	)
	(arc
		(start 100.702618 -254.329438)
		(mid 100.534062 -254.501032)
		(end 100.472494 -254.733552)
		(width 0.18288)
		(layer "In6.Cu")
		(net "M_C_CPU1_ALERT_N")
	)
	(arc
		(start 88.020144 -257.582162)
		(mid 87.799343 -257.519415)
		(end 87.575136 -257.5687)
		(width 0.18288)
		(layer "In6.Cu")
		(net "M_C_CPU1_ALERT_N")
	)
	(arc
		(start 95.538544 -257.582162)
		(mid 95.303594 -257.519202)
		(end 95.068644 -257.582162)
		(width 0.18288)
		(layer "In6.Cu")
		(net "M_C_CPU1_ALERT_N")
	)
	(arc
		(start 91.309444 -257.582162)
		(mid 91.074494 -257.645122)
		(end 90.839544 -257.582162)
		(width 0.18288)
		(layer "In6.Cu")
		(net "M_C_CPU1_ALERT_N")
	)
	(arc
		(start 100.472494 -254.747014)
		(mid 100.406271 -254.974451)
		(end 100.237544 -255.140714)
		(width 0.18288)
		(layer "In6.Cu")
		(net "M_C_CPU1_ALERT_N")
	)
	(arc
		(start 99.063048 -257.175254)
		(mid 99.001485 -257.407777)
		(end 98.832924 -257.579368)
		(width 0.18288)
		(layer "In6.Cu")
		(net "M_C_CPU1_ALERT_N")
	)
	(arc
		(start 89.899744 -257.582162)
		(mid 89.664794 -257.519202)
		(end 89.429844 -257.582162)
		(width 0.18288)
		(layer "In6.Cu")
		(net "M_C_CPU1_ALERT_N")
	)
	(arc
		(start 99.297744 -256.768346)
		(mid 99.12944 -256.934086)
		(end 99.063048 -257.160776)
		(width 0.18288)
		(layer "In6.Cu")
		(net "M_C_CPU1_ALERT_N")
	)
	(arc
		(start 94.115382 -257.590036)
		(mid 93.886129 -257.64528)
		(end 93.658944 -257.582162)
		(width 0.18288)
		(layer "In6.Cu")
		(net "M_C_CPU1_ALERT_N")
	)
	(arc
		(start 93.189044 -257.582162)
		(mid 92.954094 -257.645122)
		(end 92.719144 -257.582162)
		(width 0.18288)
		(layer "In6.Cu")
		(net "M_C_CPU1_ALERT_N")
	)
	(segment
		(start 279.816814 -243.216684)
		(end 278.711914 -243.216684)
		(width 0.20066)
		(layer "F.Cu")
		(net "M_C_CPU0_SB_RSP<1>")
	)
	(segment
		(start 344.653362 -253.383796)
		(end 344.653362 -253.919482)
		(width 0.20066)
		(layer "F.Cu")
		(net "M_C_CPU0_SB_RSP<1>")
	)
	(segment
		(start 344.653362 -253.919482)
		(end 344.653616 -253.919736)
		(width 0.20066)
		(layer "F.Cu")
		(net "M_C_CPU0_SB_RSP<1>")
	)
	(segment
		(start 342.208612 -253.904242)
		(end 342.208612 -253.928372)
		(width 0.088646)
		(layer "In6.Cu")
		(net "M_C_CPU0_SB_RSP<1>")
	)
	(segment
		(start 289.87877 -247.344184)
		(end 289.87877 -247.930416)
		(width 0.18288)
		(layer "In6.Cu")
		(net "M_C_CPU0_SB_RSP<1>")
	)
	(segment
		(start 340.156546 -254.235458)
		(end 340.141814 -254.244094)
		(width 0.088646)
		(layer "In6.Cu")
		(net "M_C_CPU0_SB_RSP<1>")
	)
	(segment
		(start 299.473874 -250.441206)
		(end 298.875704 -250.441206)
		(width 0.18288)
		(layer "In6.Cu")
		(net "M_C_CPU0_SB_RSP<1>")
	)
	(segment
		(start 288.930588 -248.113296)
		(end 288.015172 -247.19788)
		(width 0.18288)
		(layer "In6.Cu")
		(net "M_C_CPU0_SB_RSP<1>")
	)
	(segment
		(start 298.875704 -250.441206)
		(end 298.482004 -250.204986)
		(width 0.18288)
		(layer "In6.Cu")
		(net "M_C_CPU0_SB_RSP<1>")
	)
	(segment
		(start 304.045874 -251.370846)
		(end 303.916842 -251.351034)
		(width 0.18288)
		(layer "In6.Cu")
		(net "M_C_CPU0_SB_RSP<1>")
	)
	(segment
		(start 332.749144 -252.88367)
		(end 332.375002 -252.88367)
		(width 0.088646)
		(layer "In6.Cu")
		(net "M_C_CPU0_SB_RSP<1>")
	)
	(segment
		(start 286.464248 -244.85473)
		(end 286.100266 -244.490748)
		(width 0.18288)
		(layer "In6.Cu")
		(net "M_C_CPU0_SB_RSP<1>")
	)
	(segment
		(start 313.031632 -252.018038)
		(end 312.435748 -251.422154)
		(width 0.18288)
		(layer "In6.Cu")
		(net "M_C_CPU0_SB_RSP<1>")
	)
	(segment
		(start 324.593204 -254.09779)
		(end 324.587362 -254.095504)
		(width 0.18288)
		(layer "In6.Cu")
		(net "M_C_CPU0_SB_RSP<1>")
	)
	(segment
		(start 282.89123 -243.592096)
		(end 282.49118 -243.592096)
		(width 0.18288)
		(layer "In6.Cu")
		(net "M_C_CPU0_SB_RSP<1>")
	)
	(segment
		(start 295.131236 -247.891046)
		(end 294.317674 -247.891046)
		(width 0.18288)
		(layer "In6.Cu")
		(net "M_C_CPU0_SB_RSP<1>")
	)
	(segment
		(start 310.754268 -252.171708)
		(end 305.679856 -252.171708)
		(width 0.18288)
		(layer "In6.Cu")
		(net "M_C_CPU0_SB_RSP<1>")
	)
	(segment
		(start 324.587362 -254.095504)
		(end 323.394324 -253.60122)
		(width 0.18288)
		(layer "In6.Cu")
		(net "M_C_CPU0_SB_RSP<1>")
	)
	(segment
		(start 332.375002 -252.88367)
		(end 329.631802 -252.88367)
		(width 0.18288)
		(layer "In6.Cu")
		(net "M_C_CPU0_SB_RSP<1>")
	)
	(segment
		(start 341.096346 -254.235458)
		(end 341.081614 -254.244094)
		(width 0.088646)
		(layer "In6.Cu")
		(net "M_C_CPU0_SB_RSP<1>")
	)
	(segment
		(start 343.996264 -253.430278)
		(end 343.981532 -253.421642)
		(width 0.088646)
		(layer "In6.Cu")
		(net "M_C_CPU0_SB_RSP<1>")
	)
	(segment
		(start 303.916842 -251.351034)
		(end 302.867314 -251.190506)
		(width 0.18288)
		(layer "In6.Cu")
		(net "M_C_CPU0_SB_RSP<1>")
	)
	(segment
		(start 290.56965 -247.930416)
		(end 290.56965 -247.344184)
		(width 0.18288)
		(layer "In6.Cu")
		(net "M_C_CPU0_SB_RSP<1>")
	)
	(segment
		(start 290.75253 -248.113296)
		(end 290.56965 -247.930416)
		(width 0.18288)
		(layer "In6.Cu")
		(net "M_C_CPU0_SB_RSP<1>")
	)
	(segment
		(start 302.867314 -251.190506)
		(end 299.473874 -250.441206)
		(width 0.18288)
		(layer "In6.Cu")
		(net "M_C_CPU0_SB_RSP<1>")
	)
	(segment
		(start 329.631802 -252.88367)
		(end 326.379586 -254.230632)
		(width 0.18288)
		(layer "In6.Cu")
		(net "M_C_CPU0_SB_RSP<1>")
	)
	(segment
		(start 343.05621 -253.430278)
		(end 343.041478 -253.421642)
		(width 0.088646)
		(layer "In6.Cu")
		(net "M_C_CPU0_SB_RSP<1>")
	)
	(segment
		(start 304.878994 -251.370846)
		(end 304.045874 -251.370846)
		(width 0.18288)
		(layer "In6.Cu")
		(net "M_C_CPU0_SB_RSP<1>")
	)
	(segment
		(start 290.56965 -247.344184)
		(end 290.38677 -247.161304)
		(width 0.18288)
		(layer "In6.Cu")
		(net "M_C_CPU0_SB_RSP<1>")
	)
	(segment
		(start 282.17114 -244.62232)
		(end 281.22245 -244.62232)
		(width 0.18288)
		(layer "In6.Cu")
		(net "M_C_CPU0_SB_RSP<1>")
	)
	(segment
		(start 282.33116 -244.4623)
		(end 282.17114 -244.62232)
		(width 0.18288)
		(layer "In6.Cu")
		(net "M_C_CPU0_SB_RSP<1>")
	)
	(segment
		(start 289.69589 -248.113296)
		(end 288.930588 -248.113296)
		(width 0.18288)
		(layer "In6.Cu")
		(net "M_C_CPU0_SB_RSP<1>")
	)
	(segment
		(start 282.49118 -243.592096)
		(end 282.33116 -243.752116)
		(width 0.18288)
		(layer "In6.Cu")
		(net "M_C_CPU0_SB_RSP<1>")
	)
	(segment
		(start 286.464248 -246.89308)
		(end 286.464248 -244.85473)
		(width 0.18288)
		(layer "In6.Cu")
		(net "M_C_CPU0_SB_RSP<1>")
	)
	(segment
		(start 283.07411 -243.774976)
		(end 282.89123 -243.592096)
		(width 0.18288)
		(layer "In6.Cu")
		(net "M_C_CPU0_SB_RSP<1>")
	)
	(segment
		(start 281.22245 -244.62232)
		(end 279.816814 -243.216684)
		(width 0.18288)
		(layer "In6.Cu")
		(net "M_C_CPU0_SB_RSP<1>")
	)
	(segment
		(start 290.06165 -247.161304)
		(end 289.87877 -247.344184)
		(width 0.18288)
		(layer "In6.Cu")
		(net "M_C_CPU0_SB_RSP<1>")
	)
	(segment
		(start 323.394324 -253.60122)
		(end 316.853824 -253.60122)
		(width 0.18288)
		(layer "In6.Cu")
		(net "M_C_CPU0_SB_RSP<1>")
	)
	(segment
		(start 289.87877 -247.930416)
		(end 289.69589 -248.113296)
		(width 0.18288)
		(layer "In6.Cu")
		(net "M_C_CPU0_SB_RSP<1>")
	)
	(segment
		(start 286.100266 -244.490748)
		(end 283.23413 -244.490748)
		(width 0.18288)
		(layer "In6.Cu")
		(net "M_C_CPU0_SB_RSP<1>")
	)
	(segment
		(start 324.914006 -254.230632)
		(end 324.593204 -254.09779)
		(width 0.18288)
		(layer "In6.Cu")
		(net "M_C_CPU0_SB_RSP<1>")
	)
	(segment
		(start 334.050386 -254.184912)
		(end 332.749144 -252.88367)
		(width 0.088646)
		(layer "In6.Cu")
		(net "M_C_CPU0_SB_RSP<1>")
	)
	(segment
		(start 292.526212 -247.815354)
		(end 291.536374 -248.113296)
		(width 0.18288)
		(layer "In6.Cu")
		(net "M_C_CPU0_SB_RSP<1>")
	)
	(segment
		(start 298.482004 -250.204986)
		(end 297.20794 -248.819162)
		(width 0.18288)
		(layer "In6.Cu")
		(net "M_C_CPU0_SB_RSP<1>")
	)
	(segment
		(start 316.853824 -253.60122)
		(end 313.031632 -252.018038)
		(width 0.18288)
		(layer "In6.Cu")
		(net "M_C_CPU0_SB_RSP<1>")
	)
	(segment
		(start 344.00236 -253.433834)
		(end 343.996264 -253.430278)
		(width 0.088646)
		(layer "In6.Cu")
		(net "M_C_CPU0_SB_RSP<1>")
	)
	(segment
		(start 326.379586 -254.230632)
		(end 324.914006 -254.230632)
		(width 0.18288)
		(layer "In6.Cu")
		(net "M_C_CPU0_SB_RSP<1>")
	)
	(segment
		(start 294.317674 -247.891046)
		(end 292.526212 -247.815354)
		(width 0.18288)
		(layer "In6.Cu")
		(net "M_C_CPU0_SB_RSP<1>")
	)
	(segment
		(start 344.653616 -253.919736)
		(end 344.340688 -253.919736)
		(width 0.088646)
		(layer "In6.Cu")
		(net "M_C_CPU0_SB_RSP<1>")
	)
	(segment
		(start 311.503822 -251.422154)
		(end 310.754268 -252.171708)
		(width 0.18288)
		(layer "In6.Cu")
		(net "M_C_CPU0_SB_RSP<1>")
	)
	(segment
		(start 343.064592 -253.435104)
		(end 343.05621 -253.430278)
		(width 0.088646)
		(layer "In6.Cu")
		(net "M_C_CPU0_SB_RSP<1>")
	)
	(segment
		(start 291.536374 -248.113296)
		(end 290.75253 -248.113296)
		(width 0.18288)
		(layer "In6.Cu")
		(net "M_C_CPU0_SB_RSP<1>")
	)
	(segment
		(start 305.679856 -252.171708)
		(end 304.878994 -251.370846)
		(width 0.18288)
		(layer "In6.Cu")
		(net "M_C_CPU0_SB_RSP<1>")
	)
	(segment
		(start 286.769048 -247.19788)
		(end 286.464248 -246.89308)
		(width 0.18288)
		(layer "In6.Cu")
		(net "M_C_CPU0_SB_RSP<1>")
	)
	(segment
		(start 297.20794 -248.819162)
		(end 295.131236 -247.891046)
		(width 0.18288)
		(layer "In6.Cu")
		(net "M_C_CPU0_SB_RSP<1>")
	)
	(segment
		(start 283.23413 -244.490748)
		(end 283.07411 -244.330728)
		(width 0.18288)
		(layer "In6.Cu")
		(net "M_C_CPU0_SB_RSP<1>")
	)
	(segment
		(start 288.015172 -247.19788)
		(end 286.769048 -247.19788)
		(width 0.18288)
		(layer "In6.Cu")
		(net "M_C_CPU0_SB_RSP<1>")
	)
	(segment
		(start 290.38677 -247.161304)
		(end 290.06165 -247.161304)
		(width 0.18288)
		(layer "In6.Cu")
		(net "M_C_CPU0_SB_RSP<1>")
	)
	(segment
		(start 312.435748 -251.422154)
		(end 311.503822 -251.422154)
		(width 0.18288)
		(layer "In6.Cu")
		(net "M_C_CPU0_SB_RSP<1>")
	)
	(segment
		(start 338.272374 -254.237998)
		(end 338.26196 -254.244094)
		(width 0.088646)
		(layer "In6.Cu")
		(net "M_C_CPU0_SB_RSP<1>")
	)
	(segment
		(start 283.07411 -244.330728)
		(end 283.07411 -243.774976)
		(width 0.18288)
		(layer "In6.Cu")
		(net "M_C_CPU0_SB_RSP<1>")
	)
	(segment
		(start 344.340688 -253.919736)
		(end 344.275156 -253.854204)
		(width 0.088646)
		(layer "In6.Cu")
		(net "M_C_CPU0_SB_RSP<1>")
	)
	(segment
		(start 282.33116 -243.752116)
		(end 282.33116 -244.4623)
		(width 0.18288)
		(layer "In6.Cu")
		(net "M_C_CPU0_SB_RSP<1>")
	)
	(arc
		(start 342.208612 -253.928372)
		(mid 342.156342 -254.110737)
		(end 342.021414 -254.244094)
		(width 0.088646)
		(layer "In6.Cu")
		(net "M_C_CPU0_SB_RSP<1>")
	)
	(arc
		(start 335.068164 -254.244094)
		(mid 334.785462 -254.168318)
		(end 334.50276 -254.244094)
		(width 0.088646)
		(layer "In6.Cu")
		(net "M_C_CPU0_SB_RSP<1>")
	)
	(arc
		(start 336.38236 -254.244094)
		(mid 336.195162 -254.294237)
		(end 336.007964 -254.244094)
		(width 0.088646)
		(layer "In6.Cu")
		(net "M_C_CPU0_SB_RSP<1>")
	)
	(arc
		(start 339.202014 -254.244094)
		(mid 339.014816 -254.294237)
		(end 338.827618 -254.244094)
		(width 0.088646)
		(layer "In6.Cu")
		(net "M_C_CPU0_SB_RSP<1>")
	)
	(arc
		(start 342.490806 -253.430278)
		(mid 342.287983 -253.630509)
		(end 342.208612 -253.904242)
		(width 0.088646)
		(layer "In6.Cu")
		(net "M_C_CPU0_SB_RSP<1>")
	)
	(arc
		(start 343.43086 -253.430278)
		(mid 343.248355 -253.480516)
		(end 343.064592 -253.435104)
		(width 0.088646)
		(layer "In6.Cu")
		(net "M_C_CPU0_SB_RSP<1>")
	)
	(arc
		(start 336.007964 -254.244094)
		(mid 335.725262 -254.168318)
		(end 335.44256 -254.244094)
		(width 0.088646)
		(layer "In6.Cu")
		(net "M_C_CPU0_SB_RSP<1>")
	)
	(arc
		(start 339.767418 -254.244094)
		(mid 339.484716 -254.168318)
		(end 339.202014 -254.244094)
		(width 0.088646)
		(layer "In6.Cu")
		(net "M_C_CPU0_SB_RSP<1>")
	)
	(arc
		(start 342.021414 -254.244094)
		(mid 341.834216 -254.294237)
		(end 341.647018 -254.244094)
		(width 0.088646)
		(layer "In6.Cu")
		(net "M_C_CPU0_SB_RSP<1>")
	)
	(arc
		(start 344.275156 -253.854204)
		(mid 344.187912 -253.612116)
		(end 344.00236 -253.433834)
		(width 0.088646)
		(layer "In6.Cu")
		(net "M_C_CPU0_SB_RSP<1>")
	)
	(arc
		(start 340.707218 -254.244094)
		(mid 340.433019 -254.168259)
		(end 340.156546 -254.235458)
		(width 0.088646)
		(layer "In6.Cu")
		(net "M_C_CPU0_SB_RSP<1>")
	)
	(arc
		(start 334.128364 -254.244094)
		(mid 334.087434 -254.217061)
		(end 334.050386 -254.184912)
		(width 0.088646)
		(layer "In6.Cu")
		(net "M_C_CPU0_SB_RSP<1>")
	)
	(arc
		(start 341.647018 -254.244094)
		(mid 341.372819 -254.168259)
		(end 341.096346 -254.235458)
		(width 0.088646)
		(layer "In6.Cu")
		(net "M_C_CPU0_SB_RSP<1>")
	)
	(arc
		(start 337.32216 -254.244094)
		(mid 337.134962 -254.294237)
		(end 336.947764 -254.244094)
		(width 0.088646)
		(layer "In6.Cu")
		(net "M_C_CPU0_SB_RSP<1>")
	)
	(arc
		(start 343.981532 -253.421642)
		(mid 343.705057 -253.354322)
		(end 343.43086 -253.430278)
		(width 0.088646)
		(layer "In6.Cu")
		(net "M_C_CPU0_SB_RSP<1>")
	)
	(arc
		(start 341.081614 -254.244094)
		(mid 340.894416 -254.294237)
		(end 340.707218 -254.244094)
		(width 0.088646)
		(layer "In6.Cu")
		(net "M_C_CPU0_SB_RSP<1>")
	)
	(arc
		(start 335.44256 -254.244094)
		(mid 335.255362 -254.294237)
		(end 335.068164 -254.244094)
		(width 0.088646)
		(layer "In6.Cu")
		(net "M_C_CPU0_SB_RSP<1>")
	)
	(arc
		(start 338.26196 -254.244094)
		(mid 338.074762 -254.294237)
		(end 337.887564 -254.244094)
		(width 0.088646)
		(layer "In6.Cu")
		(net "M_C_CPU0_SB_RSP<1>")
	)
	(arc
		(start 338.827618 -254.244094)
		(mid 338.550805 -254.168224)
		(end 338.272374 -254.237998)
		(width 0.088646)
		(layer "In6.Cu")
		(net "M_C_CPU0_SB_RSP<1>")
	)
	(arc
		(start 337.887564 -254.244094)
		(mid 337.604862 -254.168318)
		(end 337.32216 -254.244094)
		(width 0.088646)
		(layer "In6.Cu")
		(net "M_C_CPU0_SB_RSP<1>")
	)
	(arc
		(start 343.041478 -253.421642)
		(mid 342.765003 -253.354322)
		(end 342.490806 -253.430278)
		(width 0.088646)
		(layer "In6.Cu")
		(net "M_C_CPU0_SB_RSP<1>")
	)
	(arc
		(start 336.947764 -254.244094)
		(mid 336.665062 -254.168318)
		(end 336.38236 -254.244094)
		(width 0.088646)
		(layer "In6.Cu")
		(net "M_C_CPU0_SB_RSP<1>")
	)
	(arc
		(start 334.50276 -254.244094)
		(mid 334.315562 -254.294237)
		(end 334.128364 -254.244094)
		(width 0.088646)
		(layer "In6.Cu")
		(net "M_C_CPU0_SB_RSP<1>")
	)
	(arc
		(start 340.141814 -254.244094)
		(mid 339.954616 -254.294237)
		(end 339.767418 -254.244094)
		(width 0.088646)
		(layer "In6.Cu")
		(net "M_C_CPU0_SB_RSP<1>")
	)
	(segment
		(start 345.123516 -254.197612)
		(end 345.123516 -254.733298)
		(width 0.20066)
		(layer "F.Cu")
		(net "M_C_CPU0_SB_RSP<0>")
	)
	(segment
		(start 345.123516 -254.733298)
		(end 345.123262 -254.733552)
		(width 0.20066)
		(layer "F.Cu")
		(net "M_C_CPU0_SB_RSP<0>")
	)
	(segment
		(start 272.273014 -243.216684)
		(end 271.168114 -243.216684)
		(width 0.20066)
		(layer "F.Cu")
		(net "M_C_CPU0_SB_RSP<0>")
	)
	(segment
		(start 292.923214 -249.51563)
		(end 292.620954 -249.51563)
		(width 0.18288)
		(layer "In6.Cu")
		(net "M_C_CPU0_SB_RSP<0>")
	)
	(segment
		(start 341.176864 -255.05791)
		(end 341.162132 -255.049274)
		(width 0.088646)
		(layer "In6.Cu")
		(net "M_C_CPU0_SB_RSP<0>")
	)
	(segment
		(start 323.471286 -254.75692)
		(end 323.247766 -254.664464)
		(width 0.18288)
		(layer "In6.Cu")
		(net "M_C_CPU0_SB_RSP<0>")
	)
	(segment
		(start 332.375002 -253.887224)
		(end 329.096116 -253.887224)
		(width 0.18288)
		(layer "In6.Cu")
		(net "M_C_CPU0_SB_RSP<0>")
	)
	(segment
		(start 285.38551 -247.890792)
		(end 281.375104 -247.890792)
		(width 0.18288)
		(layer "In6.Cu")
		(net "M_C_CPU0_SB_RSP<0>")
	)
	(segment
		(start 280.04389 -246.19077)
		(end 275.2471 -246.19077)
		(width 0.18288)
		(layer "In6.Cu")
		(net "M_C_CPU0_SB_RSP<0>")
	)
	(segment
		(start 316.7761 -254.66421)
		(end 313.252866 -253.20498)
		(width 0.18288)
		(layer "In6.Cu")
		(net "M_C_CPU0_SB_RSP<0>")
	)
	(segment
		(start 298.937172 -253.20498)
		(end 296.553636 -251.458476)
		(width 0.18288)
		(layer "In6.Cu")
		(net "M_C_CPU0_SB_RSP<0>")
	)
	(segment
		(start 329.096116 -253.887224)
		(end 326.610472 -254.916686)
		(width 0.18288)
		(layer "In6.Cu")
		(net "M_C_CPU0_SB_RSP<0>")
	)
	(segment
		(start 332.533752 -253.887224)
		(end 332.375002 -253.887224)
		(width 0.088646)
		(layer "In6.Cu")
		(net "M_C_CPU0_SB_RSP<0>")
	)
	(segment
		(start 319.069466 -254.664464)
		(end 319.069212 -254.66421)
		(width 0.18288)
		(layer "In6.Cu")
		(net "M_C_CPU0_SB_RSP<0>")
	)
	(segment
		(start 332.776576 -254.130048)
		(end 332.533752 -253.887224)
		(width 0.088646)
		(layer "In6.Cu")
		(net "M_C_CPU0_SB_RSP<0>")
	)
	(segment
		(start 295.080436 -249.591068)
		(end 294.482774 -249.591068)
		(width 0.18288)
		(layer "In6.Cu")
		(net "M_C_CPU0_SB_RSP<0>")
	)
	(segment
		(start 292.620954 -249.51563)
		(end 291.025834 -249.844814)
		(width 0.18288)
		(layer "In6.Cu")
		(net "M_C_CPU0_SB_RSP<0>")
	)
	(segment
		(start 285.783274 -248.288556)
		(end 285.38551 -247.890792)
		(width 0.18288)
		(layer "In6.Cu")
		(net "M_C_CPU0_SB_RSP<0>")
	)
	(segment
		(start 296.553636 -251.458476)
		(end 295.38676 -249.77725)
		(width 0.18288)
		(layer "In6.Cu")
		(net "M_C_CPU0_SB_RSP<0>")
	)
	(segment
		(start 326.610472 -254.916686)
		(end 323.856604 -254.916686)
		(width 0.18288)
		(layer "In6.Cu")
		(net "M_C_CPU0_SB_RSP<0>")
	)
	(segment
		(start 281.128216 -247.643904)
		(end 280.338276 -246.413528)
		(width 0.18288)
		(layer "In6.Cu")
		(net "M_C_CPU0_SB_RSP<0>")
	)
	(segment
		(start 323.247766 -254.664464)
		(end 319.069466 -254.664464)
		(width 0.18288)
		(layer "In6.Cu")
		(net "M_C_CPU0_SB_RSP<0>")
	)
	(segment
		(start 275.2471 -246.19077)
		(end 272.273014 -243.216684)
		(width 0.18288)
		(layer "In6.Cu")
		(net "M_C_CPU0_SB_RSP<0>")
	)
	(segment
		(start 339.297518 -255.05791)
		(end 339.287104 -255.051814)
		(width 0.088646)
		(layer "In6.Cu")
		(net "M_C_CPU0_SB_RSP<0>")
	)
	(segment
		(start 343.915746 -254.235458)
		(end 343.901014 -254.244094)
		(width 0.088646)
		(layer "In6.Cu")
		(net "M_C_CPU0_SB_RSP<0>")
	)
	(segment
		(start 295.38676 -249.77725)
		(end 295.080436 -249.591068)
		(width 0.18288)
		(layer "In6.Cu")
		(net "M_C_CPU0_SB_RSP<0>")
	)
	(segment
		(start 342.961214 -254.244094)
		(end 342.961214 -254.244348)
		(width 0.088646)
		(layer "In6.Cu")
		(net "M_C_CPU0_SB_RSP<0>")
	)
	(segment
		(start 333.580486 -254.998728)
		(end 332.776576 -254.194818)
		(width 0.088646)
		(layer "In6.Cu")
		(net "M_C_CPU0_SB_RSP<0>")
	)
	(segment
		(start 342.116664 -255.05791)
		(end 342.101932 -255.049274)
		(width 0.088646)
		(layer "In6.Cu")
		(net "M_C_CPU0_SB_RSP<0>")
	)
	(segment
		(start 323.856604 -254.916686)
		(end 323.471286 -254.75692)
		(width 0.18288)
		(layer "In6.Cu")
		(net "M_C_CPU0_SB_RSP<0>")
	)
	(segment
		(start 313.252866 -253.20498)
		(end 298.937172 -253.20498)
		(width 0.18288)
		(layer "In6.Cu")
		(net "M_C_CPU0_SB_RSP<0>")
	)
	(segment
		(start 291.025834 -249.844814)
		(end 289.539934 -249.844814)
		(width 0.18288)
		(layer "In6.Cu")
		(net "M_C_CPU0_SB_RSP<0>")
	)
	(segment
		(start 281.375104 -247.890792)
		(end 281.128216 -247.643904)
		(width 0.18288)
		(layer "In6.Cu")
		(net "M_C_CPU0_SB_RSP<0>")
	)
	(segment
		(start 280.338276 -246.413528)
		(end 280.04389 -246.19077)
		(width 0.18288)
		(layer "In6.Cu")
		(net "M_C_CPU0_SB_RSP<0>")
	)
	(segment
		(start 289.539934 -249.844814)
		(end 285.783274 -248.288556)
		(width 0.18288)
		(layer "In6.Cu")
		(net "M_C_CPU0_SB_RSP<0>")
	)
	(segment
		(start 339.682328 -255.051814)
		(end 339.671914 -255.05791)
		(width 0.088646)
		(layer "In6.Cu")
		(net "M_C_CPU0_SB_RSP<0>")
	)
	(segment
		(start 342.491314 -255.057656)
		(end 342.49106 -255.05791)
		(width 0.088646)
		(layer "In6.Cu")
		(net "M_C_CPU0_SB_RSP<0>")
	)
	(segment
		(start 332.776576 -254.194818)
		(end 332.776576 -254.130048)
		(width 0.088646)
		(layer "In6.Cu")
		(net "M_C_CPU0_SB_RSP<0>")
	)
	(segment
		(start 337.417664 -255.05791)
		(end 337.402932 -255.049274)
		(width 0.088646)
		(layer "In6.Cu")
		(net "M_C_CPU0_SB_RSP<0>")
	)
	(segment
		(start 294.482774 -249.591068)
		(end 292.923214 -249.51563)
		(width 0.18288)
		(layer "In6.Cu")
		(net "M_C_CPU0_SB_RSP<0>")
	)
	(segment
		(start 319.069212 -254.66421)
		(end 316.7761 -254.66421)
		(width 0.18288)
		(layer "In6.Cu")
		(net "M_C_CPU0_SB_RSP<0>")
	)
	(arc
		(start 342.961214 -254.244348)
		(mid 342.754359 -254.45109)
		(end 342.678512 -254.733552)
		(width 0.088646)
		(layer "In6.Cu")
		(net "M_C_CPU0_SB_RSP<0>")
	)
	(arc
		(start 343.901014 -254.244094)
		(mid 343.713816 -254.294237)
		(end 343.526618 -254.244094)
		(width 0.088646)
		(layer "In6.Cu")
		(net "M_C_CPU0_SB_RSP<0>")
	)
	(arc
		(start 341.162132 -255.049274)
		(mid 340.885691 -254.982108)
		(end 340.61146 -255.05791)
		(width 0.088646)
		(layer "In6.Cu")
		(net "M_C_CPU0_SB_RSP<0>")
	)
	(arc
		(start 342.678512 -254.733552)
		(mid 342.628348 -254.92069)
		(end 342.491314 -255.057656)
		(width 0.088646)
		(layer "In6.Cu")
		(net "M_C_CPU0_SB_RSP<0>")
	)
	(arc
		(start 345.123262 -254.733552)
		(mid 344.809085 -254.469706)
		(end 344.466418 -254.244094)
		(width 0.088646)
		(layer "In6.Cu")
		(net "M_C_CPU0_SB_RSP<0>")
	)
	(arc
		(start 338.73186 -255.05791)
		(mid 338.544662 -255.108053)
		(end 338.357464 -255.05791)
		(width 0.088646)
		(layer "In6.Cu")
		(net "M_C_CPU0_SB_RSP<0>")
	)
	(arc
		(start 337.79206 -255.05791)
		(mid 337.604862 -255.108053)
		(end 337.417664 -255.05791)
		(width 0.088646)
		(layer "In6.Cu")
		(net "M_C_CPU0_SB_RSP<0>")
	)
	(arc
		(start 342.101932 -255.049274)
		(mid 341.825491 -254.982108)
		(end 341.55126 -255.05791)
		(width 0.088646)
		(layer "In6.Cu")
		(net "M_C_CPU0_SB_RSP<0>")
	)
	(arc
		(start 340.237064 -255.05791)
		(mid 339.960505 -254.982201)
		(end 339.682328 -255.051814)
		(width 0.088646)
		(layer "In6.Cu")
		(net "M_C_CPU0_SB_RSP<0>")
	)
	(arc
		(start 342.49106 -255.05791)
		(mid 342.303862 -255.108053)
		(end 342.116664 -255.05791)
		(width 0.088646)
		(layer "In6.Cu")
		(net "M_C_CPU0_SB_RSP<0>")
	)
	(arc
		(start 344.466418 -254.244094)
		(mid 344.192219 -254.168259)
		(end 343.915746 -254.235458)
		(width 0.088646)
		(layer "In6.Cu")
		(net "M_C_CPU0_SB_RSP<0>")
	)
	(arc
		(start 333.658464 -255.05791)
		(mid 333.617534 -255.030877)
		(end 333.580486 -254.998728)
		(width 0.088646)
		(layer "In6.Cu")
		(net "M_C_CPU0_SB_RSP<0>")
	)
	(arc
		(start 334.03286 -255.05791)
		(mid 333.845662 -255.108053)
		(end 333.658464 -255.05791)
		(width 0.088646)
		(layer "In6.Cu")
		(net "M_C_CPU0_SB_RSP<0>")
	)
	(arc
		(start 343.526618 -254.244094)
		(mid 343.243916 -254.168318)
		(end 342.961214 -254.244094)
		(width 0.088646)
		(layer "In6.Cu")
		(net "M_C_CPU0_SB_RSP<0>")
	)
	(arc
		(start 337.402932 -255.049274)
		(mid 337.126491 -254.982108)
		(end 336.85226 -255.05791)
		(width 0.088646)
		(layer "In6.Cu")
		(net "M_C_CPU0_SB_RSP<0>")
	)
	(arc
		(start 340.61146 -255.05791)
		(mid 340.424262 -255.108053)
		(end 340.237064 -255.05791)
		(width 0.088646)
		(layer "In6.Cu")
		(net "M_C_CPU0_SB_RSP<0>")
	)
	(arc
		(start 335.91246 -255.05791)
		(mid 335.725262 -255.108053)
		(end 335.538064 -255.05791)
		(width 0.088646)
		(layer "In6.Cu")
		(net "M_C_CPU0_SB_RSP<0>")
	)
	(arc
		(start 334.97266 -255.05791)
		(mid 334.785462 -255.108053)
		(end 334.598264 -255.05791)
		(width 0.088646)
		(layer "In6.Cu")
		(net "M_C_CPU0_SB_RSP<0>")
	)
	(arc
		(start 341.55126 -255.05791)
		(mid 341.364062 -255.108053)
		(end 341.176864 -255.05791)
		(width 0.088646)
		(layer "In6.Cu")
		(net "M_C_CPU0_SB_RSP<0>")
	)
	(arc
		(start 339.671914 -255.05791)
		(mid 339.484716 -255.108053)
		(end 339.297518 -255.05791)
		(width 0.088646)
		(layer "In6.Cu")
		(net "M_C_CPU0_SB_RSP<0>")
	)
	(arc
		(start 336.85226 -255.05791)
		(mid 336.665062 -255.108053)
		(end 336.477864 -255.05791)
		(width 0.088646)
		(layer "In6.Cu")
		(net "M_C_CPU0_SB_RSP<0>")
	)
	(arc
		(start 339.287104 -255.051814)
		(mid 339.008672 -254.982)
		(end 338.73186 -255.05791)
		(width 0.088646)
		(layer "In6.Cu")
		(net "M_C_CPU0_SB_RSP<0>")
	)
	(arc
		(start 338.357464 -255.05791)
		(mid 338.074762 -254.982168)
		(end 337.79206 -255.05791)
		(width 0.088646)
		(layer "In6.Cu")
		(net "M_C_CPU0_SB_RSP<0>")
	)
	(arc
		(start 336.477864 -255.05791)
		(mid 336.195162 -254.982168)
		(end 335.91246 -255.05791)
		(width 0.088646)
		(layer "In6.Cu")
		(net "M_C_CPU0_SB_RSP<0>")
	)
	(arc
		(start 335.538064 -255.05791)
		(mid 335.255362 -254.982168)
		(end 334.97266 -255.05791)
		(width 0.088646)
		(layer "In6.Cu")
		(net "M_C_CPU0_SB_RSP<0>")
	)
	(arc
		(start 334.598264 -255.05791)
		(mid 334.315562 -254.982168)
		(end 334.03286 -255.05791)
		(width 0.088646)
		(layer "In6.Cu")
		(net "M_C_CPU0_SB_RSP<0>")
	)
	(segment
		(start 280.606246 -246.892572)
		(end 280.457148 -247.04167)
		(width 0.20066)
		(layer "F.Cu")
		(net "M_C_CPU0_SB_PAR")
	)
	(segment
		(start 280.606246 -246.740934)
		(end 280.606246 -246.892572)
		(width 0.20066)
		(layer "F.Cu")
		(net "M_C_CPU0_SB_PAR")
	)
	(segment
		(start 280.73477 -246.61241)
		(end 280.606246 -246.740934)
		(width 0.20066)
		(layer "F.Cu")
		(net "M_C_CPU0_SB_PAR")
	)
	(segment
		(start 280.457148 -247.04167)
		(end 279.912826 -247.04167)
		(width 0.20066)
		(layer "F.Cu")
		(net "M_C_CPU0_SB_PAR")
	)
	(segment
		(start 281.788362 -246.824246)
		(end 281.34183 -246.824246)
		(width 0.20066)
		(layer "F.Cu")
		(net "M_C_CPU0_SB_PAR")
	)
	(segment
		(start 277.601934 -247.04167)
		(end 277.58771 -247.055894)
		(width 0.101854)
		(layer "F.Cu")
		(net "M_C_CPU0_SB_PAR")
	)
	(segment
		(start 342.194134 -245.27256)
		(end 342.19388 -245.272306)
		(width 0.20066)
		(layer "F.Cu")
		(net "M_C_CPU0_SB_PAR")
	)
	(segment
		(start 277.839932 -247.04167)
		(end 277.601934 -247.04167)
		(width 0.101854)
		(layer "F.Cu")
		(net "M_C_CPU0_SB_PAR")
	)
	(segment
		(start 277.091394 -246.9134)
		(end 277.091394 -246.742712)
		(width 0.20066)
		(layer "F.Cu")
		(net "M_C_CPU0_SB_PAR")
	)
	(segment
		(start 277.233888 -247.055894)
		(end 277.091394 -246.9134)
		(width 0.20066)
		(layer "F.Cu")
		(net "M_C_CPU0_SB_PAR")
	)
	(segment
		(start 277.091394 -246.742712)
		(end 276.96541 -246.616728)
		(width 0.20066)
		(layer "F.Cu")
		(net "M_C_CPU0_SB_PAR")
	)
	(segment
		(start 281.34183 -246.824246)
		(end 281.129994 -246.61241)
		(width 0.20066)
		(layer "F.Cu")
		(net "M_C_CPU0_SB_PAR")
	)
	(segment
		(start 281.99588 -246.616728)
		(end 281.788362 -246.824246)
		(width 0.20066)
		(layer "F.Cu")
		(net "M_C_CPU0_SB_PAR")
	)
	(segment
		(start 277.58771 -247.055894)
		(end 277.233888 -247.055894)
		(width 0.20066)
		(layer "F.Cu")
		(net "M_C_CPU0_SB_PAR")
	)
	(segment
		(start 281.129994 -246.61241)
		(end 280.73477 -246.61241)
		(width 0.20066)
		(layer "F.Cu")
		(net "M_C_CPU0_SB_PAR")
	)
	(segment
		(start 342.19388 -245.272306)
		(end 342.19388 -244.73662)
		(width 0.20066)
		(layer "F.Cu")
		(net "M_C_CPU0_SB_PAR")
	)
	(segment
		(start 276.96541 -246.616728)
		(end 275.268182 -246.616728)
		(width 0.20066)
		(layer "F.Cu")
		(net "M_C_CPU0_SB_PAR")
	)
	(segment
		(start 279.912826 -247.04167)
		(end 277.839932 -247.04167)
		(width 0.1016)
		(layer "F.Cu")
		(net "M_C_CPU0_SB_PAR")
	)
	(segment
		(start 282.811982 -246.616728)
		(end 281.99588 -246.616728)
		(width 0.20066)
		(layer "F.Cu")
		(net "M_C_CPU0_SB_PAR")
	)
	(segment
		(start 283.916882 -246.616728)
		(end 282.811982 -246.616728)
		(width 0.20066)
		(layer "F.Cu")
		(net "M_C_CPU0_SB_PAR")
	)
	(segment
		(start 339.187536 -244.412262)
		(end 338.901278 -244.577616)
		(width 0.088646)
		(layer "In4.Cu")
		(net "M_C_CPU0_SB_PAR")
	)
	(segment
		(start 338.247736 -245.060978)
		(end 338.237322 -245.054882)
		(width 0.088646)
		(layer "In4.Cu")
		(net "M_C_CPU0_SB_PAR")
	)
	(segment
		(start 315.013086 -246.51335)
		(end 314.733432 -246.793004)
		(width 0.18288)
		(layer "In4.Cu")
		(net "M_C_CPU0_SB_PAR")
	)
	(segment
		(start 331.856334 -246.73941)
		(end 331.563218 -246.73941)
		(width 0.088646)
		(layer "In4.Cu")
		(net "M_C_CPU0_SB_PAR")
	)
	(segment
		(start 299.633894 -247.04167)
		(end 287.026604 -247.04167)
		(width 0.18288)
		(layer "In4.Cu")
		(net "M_C_CPU0_SB_PAR")
	)
	(segment
		(start 300.730412 -247.22836)
		(end 299.820584 -247.22836)
		(width 0.18288)
		(layer "In4.Cu")
		(net "M_C_CPU0_SB_PAR")
	)
	(segment
		(start 334.580484 -245.528592)
		(end 334.580484 -245.55069)
		(width 0.088646)
		(layer "In4.Cu")
		(net "M_C_CPU0_SB_PAR")
	)
	(segment
		(start 299.820584 -247.22836)
		(end 299.633894 -247.04167)
		(width 0.18288)
		(layer "In4.Cu")
		(net "M_C_CPU0_SB_PAR")
	)
	(segment
		(start 341.46998 -244.428772)
		(end 341.441532 -244.412262)
		(width 0.088646)
		(layer "In4.Cu")
		(net "M_C_CPU0_SB_PAR")
	)
	(segment
		(start 310.734456 -247.281192)
		(end 309.38089 -247.281192)
		(width 0.18288)
		(layer "In4.Cu")
		(net "M_C_CPU0_SB_PAR")
	)
	(segment
		(start 285.358078 -247.055132)
		(end 284.355286 -247.055132)
		(width 0.18288)
		(layer "In4.Cu")
		(net "M_C_CPU0_SB_PAR")
	)
	(segment
		(start 336.367374 -245.060724)
		(end 336.367882 -245.060978)
		(width 0.088646)
		(layer "In4.Cu")
		(net "M_C_CPU0_SB_PAR")
	)
	(segment
		(start 308.32425 -247.281192)
		(end 307.611018 -247.281192)
		(width 0.18288)
		(layer "In4.Cu")
		(net "M_C_CPU0_SB_PAR")
	)
	(segment
		(start 309.01513 -246.699278)
		(end 308.69001 -246.699278)
		(width 0.18288)
		(layer "In4.Cu")
		(net "M_C_CPU0_SB_PAR")
	)
	(segment
		(start 284.355286 -247.055132)
		(end 283.916882 -246.616728)
		(width 0.18288)
		(layer "In4.Cu")
		(net "M_C_CPU0_SB_PAR")
	)
	(segment
		(start 305.21148 -247.26773)
		(end 304.871882 -246.928132)
		(width 0.18288)
		(layer "In4.Cu")
		(net "M_C_CPU0_SB_PAR")
	)
	(segment
		(start 333.932022 -246.683784)
		(end 333.923132 -246.688864)
		(width 0.088646)
		(layer "In4.Cu")
		(net "M_C_CPU0_SB_PAR")
	)
	(segment
		(start 334.110584 -246.3546)
		(end 334.110584 -246.364506)
		(width 0.088646)
		(layer "In4.Cu")
		(net "M_C_CPU0_SB_PAR")
	)
	(segment
		(start 335.428082 -245.060978)
		(end 335.41335 -245.052342)
		(width 0.088646)
		(layer "In4.Cu")
		(net "M_C_CPU0_SB_PAR")
	)
	(segment
		(start 301.604172 -247.04548)
		(end 301.604172 -246.903748)
		(width 0.18288)
		(layer "In4.Cu")
		(net "M_C_CPU0_SB_PAR")
	)
	(segment
		(start 311.222644 -246.793004)
		(end 310.734456 -247.281192)
		(width 0.18288)
		(layer "In4.Cu")
		(net "M_C_CPU0_SB_PAR")
	)
	(segment
		(start 308.50713 -247.098312)
		(end 308.32425 -247.281192)
		(width 0.18288)
		(layer "In4.Cu")
		(net "M_C_CPU0_SB_PAR")
	)
	(segment
		(start 336.367882 -245.060978)
		(end 336.35315 -245.052342)
		(width 0.088646)
		(layer "In4.Cu")
		(net "M_C_CPU0_SB_PAR")
	)
	(segment
		(start 301.421292 -246.720868)
		(end 301.096172 -246.720868)
		(width 0.18288)
		(layer "In4.Cu")
		(net "M_C_CPU0_SB_PAR")
	)
	(segment
		(start 285.67253 -246.74068)
		(end 285.358078 -247.055132)
		(width 0.18288)
		(layer "In4.Cu")
		(net "M_C_CPU0_SB_PAR")
	)
	(segment
		(start 308.69001 -246.699278)
		(end 308.50713 -246.882158)
		(width 0.18288)
		(layer "In4.Cu")
		(net "M_C_CPU0_SB_PAR")
	)
	(segment
		(start 304.871882 -246.928132)
		(end 303.853596 -246.928132)
		(width 0.18288)
		(layer "In4.Cu")
		(net "M_C_CPU0_SB_PAR")
	)
	(segment
		(start 334.401922 -245.869968)
		(end 334.393032 -245.875048)
		(width 0.088646)
		(layer "In4.Cu")
		(net "M_C_CPU0_SB_PAR")
	)
	(segment
		(start 300.913292 -246.903748)
		(end 300.913292 -247.04548)
		(width 0.18288)
		(layer "In4.Cu")
		(net "M_C_CPU0_SB_PAR")
	)
	(segment
		(start 336.742278 -245.060978)
		(end 336.741262 -245.06174)
		(width 0.088646)
		(layer "In4.Cu")
		(net "M_C_CPU0_SB_PAR")
	)
	(segment
		(start 307.257958 -246.928132)
		(end 305.90236 -246.928132)
		(width 0.18288)
		(layer "In4.Cu")
		(net "M_C_CPU0_SB_PAR")
	)
	(segment
		(start 308.50713 -246.882158)
		(end 308.50713 -247.098312)
		(width 0.18288)
		(layer "In4.Cu")
		(net "M_C_CPU0_SB_PAR")
	)
	(segment
		(start 303.553368 -247.22836)
		(end 301.787052 -247.22836)
		(width 0.18288)
		(layer "In4.Cu")
		(net "M_C_CPU0_SB_PAR")
	)
	(segment
		(start 301.604172 -246.903748)
		(end 301.421292 -246.720868)
		(width 0.18288)
		(layer "In4.Cu")
		(net "M_C_CPU0_SB_PAR")
	)
	(segment
		(start 340.127336 -244.412262)
		(end 340.116922 -244.418358)
		(width 0.088646)
		(layer "In4.Cu")
		(net "M_C_CPU0_SB_PAR")
	)
	(segment
		(start 301.787052 -247.22836)
		(end 301.604172 -247.04548)
		(width 0.18288)
		(layer "In4.Cu")
		(net "M_C_CPU0_SB_PAR")
	)
	(segment
		(start 331.337158 -246.51335)
		(end 331.004418 -246.51335)
		(width 0.088646)
		(layer "In4.Cu")
		(net "M_C_CPU0_SB_PAR")
	)
	(segment
		(start 309.38089 -247.281192)
		(end 309.19801 -247.098312)
		(width 0.18288)
		(layer "In4.Cu")
		(net "M_C_CPU0_SB_PAR")
	)
	(segment
		(start 341.067136 -244.412262)
		(end 341.066882 -244.412262)
		(width 0.088646)
		(layer "In4.Cu")
		(net "M_C_CPU0_SB_PAR")
	)
	(segment
		(start 287.026604 -247.04167)
		(end 286.725614 -246.74068)
		(width 0.18288)
		(layer "In4.Cu")
		(net "M_C_CPU0_SB_PAR")
	)
	(segment
		(start 314.733432 -246.793004)
		(end 311.222644 -246.793004)
		(width 0.18288)
		(layer "In4.Cu")
		(net "M_C_CPU0_SB_PAR")
	)
	(segment
		(start 307.611018 -247.281192)
		(end 307.257958 -246.928132)
		(width 0.18288)
		(layer "In4.Cu")
		(net "M_C_CPU0_SB_PAR")
	)
	(segment
		(start 286.725614 -246.74068)
		(end 285.67253 -246.74068)
		(width 0.18288)
		(layer "In4.Cu")
		(net "M_C_CPU0_SB_PAR")
	)
	(segment
		(start 331.004418 -246.51335)
		(end 315.013086 -246.51335)
		(width 0.18288)
		(layer "In4.Cu")
		(net "M_C_CPU0_SB_PAR")
	)
	(segment
		(start 301.096172 -246.720868)
		(end 300.913292 -246.903748)
		(width 0.18288)
		(layer "In4.Cu")
		(net "M_C_CPU0_SB_PAR")
	)
	(segment
		(start 342.19388 -244.73662)
		(end 341.46998 -244.428772)
		(width 0.088646)
		(layer "In4.Cu")
		(net "M_C_CPU0_SB_PAR")
	)
	(segment
		(start 338.80933 -244.73662)
		(end 338.80933 -244.736874)
		(width 0.088646)
		(layer "In4.Cu")
		(net "M_C_CPU0_SB_PAR")
	)
	(segment
		(start 305.562762 -247.26773)
		(end 305.21148 -247.26773)
		(width 0.18288)
		(layer "In4.Cu")
		(net "M_C_CPU0_SB_PAR")
	)
	(segment
		(start 300.913292 -247.04548)
		(end 300.730412 -247.22836)
		(width 0.18288)
		(layer "In4.Cu")
		(net "M_C_CPU0_SB_PAR")
	)
	(segment
		(start 331.563218 -246.73941)
		(end 331.337158 -246.51335)
		(width 0.088646)
		(layer "In4.Cu")
		(net "M_C_CPU0_SB_PAR")
	)
	(segment
		(start 337.307682 -245.060978)
		(end 337.29295 -245.052342)
		(width 0.088646)
		(layer "In4.Cu")
		(net "M_C_CPU0_SB_PAR")
	)
	(segment
		(start 303.853596 -246.928132)
		(end 303.553368 -247.22836)
		(width 0.18288)
		(layer "In4.Cu")
		(net "M_C_CPU0_SB_PAR")
	)
	(segment
		(start 305.90236 -246.928132)
		(end 305.562762 -247.26773)
		(width 0.18288)
		(layer "In4.Cu")
		(net "M_C_CPU0_SB_PAR")
	)
	(segment
		(start 309.19801 -246.882158)
		(end 309.01513 -246.699278)
		(width 0.18288)
		(layer "In4.Cu")
		(net "M_C_CPU0_SB_PAR")
	)
	(segment
		(start 309.19801 -247.098312)
		(end 309.19801 -246.882158)
		(width 0.18288)
		(layer "In4.Cu")
		(net "M_C_CPU0_SB_PAR")
	)
	(arc
		(start 338.901278 -244.577616)
		(mid 338.833948 -244.644774)
		(end 338.80933 -244.73662)
		(width 0.088646)
		(layer "In4.Cu")
		(net "M_C_CPU0_SB_PAR")
	)
	(arc
		(start 340.501732 -244.412262)
		(mid 340.314534 -244.362119)
		(end 340.127336 -244.412262)
		(width 0.088646)
		(layer "In4.Cu")
		(net "M_C_CPU0_SB_PAR")
	)
	(arc
		(start 338.622132 -245.060978)
		(mid 338.434934 -245.111121)
		(end 338.247736 -245.060978)
		(width 0.088646)
		(layer "In4.Cu")
		(net "M_C_CPU0_SB_PAR")
	)
	(arc
		(start 341.441532 -244.412262)
		(mid 341.254334 -244.362085)
		(end 341.067136 -244.412262)
		(width 0.088646)
		(layer "In4.Cu")
		(net "M_C_CPU0_SB_PAR")
	)
	(arc
		(start 338.237322 -245.054882)
		(mid 337.95889 -244.985068)
		(end 337.682078 -245.060978)
		(width 0.088646)
		(layer "In4.Cu")
		(net "M_C_CPU0_SB_PAR")
	)
	(arc
		(start 340.116922 -244.418358)
		(mid 339.83849 -244.488204)
		(end 339.561678 -244.412262)
		(width 0.088646)
		(layer "In4.Cu")
		(net "M_C_CPU0_SB_PAR")
	)
	(arc
		(start 334.393032 -245.875048)
		(mid 334.188697 -246.077653)
		(end 334.110584 -246.3546)
		(width 0.088646)
		(layer "In4.Cu")
		(net "M_C_CPU0_SB_PAR")
	)
	(arc
		(start 336.741262 -245.06174)
		(mid 336.554166 -245.111274)
		(end 336.367374 -245.060724)
		(width 0.088646)
		(layer "In4.Cu")
		(net "M_C_CPU0_SB_PAR")
	)
	(arc
		(start 334.110584 -246.364506)
		(mid 334.062905 -246.547406)
		(end 333.932022 -246.683784)
		(width 0.088646)
		(layer "In4.Cu")
		(net "M_C_CPU0_SB_PAR")
	)
	(arc
		(start 333.923132 -246.688864)
		(mid 333.735934 -246.739007)
		(end 333.548736 -246.688864)
		(width 0.088646)
		(layer "In4.Cu")
		(net "M_C_CPU0_SB_PAR")
	)
	(arc
		(start 334.862678 -245.060978)
		(mid 334.661396 -245.258465)
		(end 334.580484 -245.528592)
		(width 0.088646)
		(layer "In4.Cu")
		(net "M_C_CPU0_SB_PAR")
	)
	(arc
		(start 337.29295 -245.052342)
		(mid 337.016509 -244.985176)
		(end 336.742278 -245.060978)
		(width 0.088646)
		(layer "In4.Cu")
		(net "M_C_CPU0_SB_PAR")
	)
	(arc
		(start 338.80933 -244.736874)
		(mid 338.759166 -244.924012)
		(end 338.622132 -245.060978)
		(width 0.088646)
		(layer "In4.Cu")
		(net "M_C_CPU0_SB_PAR")
	)
	(arc
		(start 337.682078 -245.060978)
		(mid 337.49488 -245.111121)
		(end 337.307682 -245.060978)
		(width 0.088646)
		(layer "In4.Cu")
		(net "M_C_CPU0_SB_PAR")
	)
	(arc
		(start 332.043532 -246.688864)
		(mid 331.95326 -246.726463)
		(end 331.856334 -246.73941)
		(width 0.088646)
		(layer "In4.Cu")
		(net "M_C_CPU0_SB_PAR")
	)
	(arc
		(start 332.983332 -246.688864)
		(mid 332.796134 -246.739007)
		(end 332.608936 -246.688864)
		(width 0.088646)
		(layer "In4.Cu")
		(net "M_C_CPU0_SB_PAR")
	)
	(arc
		(start 332.608936 -246.688864)
		(mid 332.326234 -246.613088)
		(end 332.043532 -246.688864)
		(width 0.088646)
		(layer "In4.Cu")
		(net "M_C_CPU0_SB_PAR")
	)
	(arc
		(start 334.580484 -245.55069)
		(mid 334.532805 -245.73359)
		(end 334.401922 -245.869968)
		(width 0.088646)
		(layer "In4.Cu")
		(net "M_C_CPU0_SB_PAR")
	)
	(arc
		(start 336.35315 -245.052342)
		(mid 336.076709 -244.985176)
		(end 335.802478 -245.060978)
		(width 0.088646)
		(layer "In4.Cu")
		(net "M_C_CPU0_SB_PAR")
	)
	(arc
		(start 335.802478 -245.060978)
		(mid 335.61528 -245.111121)
		(end 335.428082 -245.060978)
		(width 0.088646)
		(layer "In4.Cu")
		(net "M_C_CPU0_SB_PAR")
	)
	(arc
		(start 341.066882 -244.412262)
		(mid 340.784324 -244.487911)
		(end 340.501732 -244.412262)
		(width 0.088646)
		(layer "In4.Cu")
		(net "M_C_CPU0_SB_PAR")
	)
	(arc
		(start 333.548736 -246.688864)
		(mid 333.266034 -246.613088)
		(end 332.983332 -246.688864)
		(width 0.088646)
		(layer "In4.Cu")
		(net "M_C_CPU0_SB_PAR")
	)
	(arc
		(start 339.561678 -244.412262)
		(mid 339.374624 -244.362212)
		(end 339.187536 -244.412262)
		(width 0.088646)
		(layer "In4.Cu")
		(net "M_C_CPU0_SB_PAR")
	)
	(arc
		(start 335.41335 -245.052342)
		(mid 335.136909 -244.985176)
		(end 334.862678 -245.060978)
		(width 0.088646)
		(layer "In4.Cu")
		(net "M_C_CPU0_SB_PAR")
	)
	(segment
		(start 340.314534 -240.389156)
		(end 340.314534 -239.85347)
		(width 0.20066)
		(layer "F.Cu")
		(net "M_C_CPU0_SB_DQS_DP<9>")
	)
	(segment
		(start 274.390358 -238.541814)
		(end 274.005802 -238.541814)
		(width 0.101854)
		(layer "F.Cu")
		(net "M_C_CPU0_SB_DQS_DP<9>")
	)
	(segment
		(start 276.530562 -238.541814)
		(end 276.469348 -238.541814)
		(width 0.101854)
		(layer "F.Cu")
		(net "M_C_CPU0_SB_DQS_DP<9>")
	)
	(segment
		(start 276.62124 -238.541814)
		(end 276.530562 -238.541814)
		(width 0.20066)
		(layer "F.Cu")
		(net "M_C_CPU0_SB_DQS_DP<9>")
	)
	(segment
		(start 277.902162 -237.855506)
		(end 277.63343 -237.855506)
		(width 0.20066)
		(layer "F.Cu")
		(net "M_C_CPU0_SB_DQS_DP<9>")
	)
	(segment
		(start 276.469348 -238.541814)
		(end 274.390358 -238.541814)
		(width 0.1016)
		(layer "F.Cu")
		(net "M_C_CPU0_SB_DQS_DP<9>")
	)
	(segment
		(start 273.916394 -238.541814)
		(end 273.655282 -238.280702)
		(width 0.20066)
		(layer "F.Cu")
		(net "M_C_CPU0_SB_DQS_DP<9>")
	)
	(segment
		(start 273.028156 -238.280702)
		(end 272.39214 -237.855506)
		(width 0.20066)
		(layer "F.Cu")
		(net "M_C_CPU0_SB_DQS_DP<9>")
	)
	(segment
		(start 277.208234 -238.280702)
		(end 276.882352 -238.280702)
		(width 0.20066)
		(layer "F.Cu")
		(net "M_C_CPU0_SB_DQS_DP<9>")
	)
	(segment
		(start 271.706086 -238.116618)
		(end 271.168114 -238.116618)
		(width 0.20066)
		(layer "F.Cu")
		(net "M_C_CPU0_SB_DQS_DP<9>")
	)
	(segment
		(start 340.314534 -239.85347)
		(end 340.31428 -239.853216)
		(width 0.20066)
		(layer "F.Cu")
		(net "M_C_CPU0_SB_DQS_DP<9>")
	)
	(segment
		(start 276.882352 -238.280702)
		(end 276.62124 -238.541814)
		(width 0.20066)
		(layer "F.Cu")
		(net "M_C_CPU0_SB_DQS_DP<9>")
	)
	(segment
		(start 272.39214 -237.855506)
		(end 271.967198 -237.855506)
		(width 0.20066)
		(layer "F.Cu")
		(net "M_C_CPU0_SB_DQS_DP<9>")
	)
	(segment
		(start 274.005802 -238.541814)
		(end 273.916394 -238.541814)
		(width 0.20066)
		(layer "F.Cu")
		(net "M_C_CPU0_SB_DQS_DP<9>")
	)
	(segment
		(start 277.63343 -237.855506)
		(end 277.208234 -238.280702)
		(width 0.20066)
		(layer "F.Cu")
		(net "M_C_CPU0_SB_DQS_DP<9>")
	)
	(segment
		(start 278.163274 -238.116618)
		(end 277.902162 -237.855506)
		(width 0.20066)
		(layer "F.Cu")
		(net "M_C_CPU0_SB_DQS_DP<9>")
	)
	(segment
		(start 278.711914 -238.116618)
		(end 278.163274 -238.116618)
		(width 0.20066)
		(layer "F.Cu")
		(net "M_C_CPU0_SB_DQS_DP<9>")
	)
	(segment
		(start 271.967198 -237.855506)
		(end 271.706086 -238.116618)
		(width 0.20066)
		(layer "F.Cu")
		(net "M_C_CPU0_SB_DQS_DP<9>")
	)
	(segment
		(start 273.655282 -238.280702)
		(end 273.028156 -238.280702)
		(width 0.20066)
		(layer "F.Cu")
		(net "M_C_CPU0_SB_DQS_DP<9>")
	)
	(segment
		(start 279.816814 -238.116618)
		(end 278.711914 -238.116618)
		(width 0.20066)
		(layer "F.Cu")
		(net "M_C_CPU0_SB_DQS_DP<9>")
	)
	(segment
		(start 288.582862 -237.642146)
		(end 287.952434 -238.272574)
		(width 0.18288)
		(layer "In4.Cu")
		(net "M_C_CPU0_SB_DQS_DP<9>")
	)
	(segment
		(start 298.806616 -238.541814)
		(end 298.53128 -238.266478)
		(width 0.18288)
		(layer "In4.Cu")
		(net "M_C_CPU0_SB_DQS_DP<9>")
	)
	(segment
		(start 336.837782 -240.342928)
		(end 336.83321 -240.345468)
		(width 0.088646)
		(layer "In4.Cu")
		(net "M_C_CPU0_SB_DQS_DP<9>")
	)
	(segment
		(start 280.098246 -237.835186)
		(end 279.816814 -238.116618)
		(width 0.18288)
		(layer "In4.Cu")
		(net "M_C_CPU0_SB_DQS_DP<9>")
	)
	(segment
		(start 280.779982 -237.54969)
		(end 280.494486 -237.835186)
		(width 0.18288)
		(layer "In4.Cu")
		(net "M_C_CPU0_SB_DQS_DP<9>")
	)
	(segment
		(start 282.126182 -237.54969)
		(end 280.779982 -237.54969)
		(width 0.18288)
		(layer "In4.Cu")
		(net "M_C_CPU0_SB_DQS_DP<9>")
	)
	(segment
		(start 294.436292 -239.116616)
		(end 293.9415 -239.116616)
		(width 0.18288)
		(layer "In4.Cu")
		(net "M_C_CPU0_SB_DQS_DP<9>")
	)
	(segment
		(start 297.126914 -239.12576)
		(end 295.354248 -239.12576)
		(width 0.18288)
		(layer "In4.Cu")
		(net "M_C_CPU0_SB_DQS_DP<9>")
	)
	(segment
		(start 287.952434 -238.272574)
		(end 284.461712 -238.272574)
		(width 0.18288)
		(layer "In4.Cu")
		(net "M_C_CPU0_SB_DQS_DP<9>")
	)
	(segment
		(start 299.442886 -238.280956)
		(end 299.182028 -238.541814)
		(width 0.18288)
		(layer "In4.Cu")
		(net "M_C_CPU0_SB_DQS_DP<9>")
	)
	(segment
		(start 339.97392 -239.943132)
		(end 339.548724 -240.18494)
		(width 0.088646)
		(layer "In4.Cu")
		(net "M_C_CPU0_SB_DQS_DP<9>")
	)
	(segment
		(start 299.182028 -238.541814)
		(end 298.806616 -238.541814)
		(width 0.18288)
		(layer "In4.Cu")
		(net "M_C_CPU0_SB_DQS_DP<9>")
	)
	(segment
		(start 339.287104 -240.219738)
		(end 339.282278 -240.222278)
		(width 0.088646)
		(layer "In4.Cu")
		(net "M_C_CPU0_SB_DQS_DP<9>")
	)
	(segment
		(start 280.494486 -237.835186)
		(end 280.098246 -237.835186)
		(width 0.18288)
		(layer "In4.Cu")
		(net "M_C_CPU0_SB_DQS_DP<9>")
	)
	(segment
		(start 310.850788 -238.496856)
		(end 309.636414 -238.496856)
		(width 0.18288)
		(layer "In4.Cu")
		(net "M_C_CPU0_SB_DQS_DP<9>")
	)
	(segment
		(start 331.097636 -241.525806)
		(end 331.037692 -241.58575)
		(width 0.088646)
		(layer "In4.Cu")
		(net "M_C_CPU0_SB_DQS_DP<9>")
	)
	(segment
		(start 308.718458 -237.5789)
		(end 303.964848 -237.5789)
		(width 0.18288)
		(layer "In4.Cu")
		(net "M_C_CPU0_SB_DQS_DP<9>")
	)
	(segment
		(start 295.088056 -239.391952)
		(end 294.711628 -239.391952)
		(width 0.18288)
		(layer "In4.Cu")
		(net "M_C_CPU0_SB_DQS_DP<9>")
	)
	(segment
		(start 295.354248 -239.12576)
		(end 295.088056 -239.391952)
		(width 0.18288)
		(layer "In4.Cu")
		(net "M_C_CPU0_SB_DQS_DP<9>")
	)
	(segment
		(start 311.23128 -238.877348)
		(end 310.850788 -238.496856)
		(width 0.18288)
		(layer "In4.Cu")
		(net "M_C_CPU0_SB_DQS_DP<9>")
	)
	(segment
		(start 292.46703 -237.642146)
		(end 288.582862 -237.642146)
		(width 0.18288)
		(layer "In4.Cu")
		(net "M_C_CPU0_SB_DQS_DP<9>")
	)
	(segment
		(start 331.004164 -241.58575)
		(end 318.314578 -241.58575)
		(width 0.18288)
		(layer "In4.Cu")
		(net "M_C_CPU0_SB_DQS_DP<9>")
	)
	(segment
		(start 336.841592 -240.340642)
		(end 336.837782 -240.342928)
		(width 0.088646)
		(layer "In4.Cu")
		(net "M_C_CPU0_SB_DQS_DP<9>")
	)
	(segment
		(start 339.282278 -240.222278)
		(end 338.926678 -240.222278)
		(width 0.088646)
		(layer "In4.Cu")
		(net "M_C_CPU0_SB_DQS_DP<9>")
	)
	(segment
		(start 332.220824 -241.525806)
		(end 331.097636 -241.525806)
		(width 0.088646)
		(layer "In4.Cu")
		(net "M_C_CPU0_SB_DQS_DP<9>")
	)
	(segment
		(start 293.9415 -239.116616)
		(end 292.46703 -237.642146)
		(width 0.18288)
		(layer "In4.Cu")
		(net "M_C_CPU0_SB_DQS_DP<9>")
	)
	(segment
		(start 303.262792 -238.280956)
		(end 299.442886 -238.280956)
		(width 0.18288)
		(layer "In4.Cu")
		(net "M_C_CPU0_SB_DQS_DP<9>")
	)
	(segment
		(start 284.461712 -238.272574)
		(end 284.192472 -238.541814)
		(width 0.18288)
		(layer "In4.Cu")
		(net "M_C_CPU0_SB_DQS_DP<9>")
	)
	(segment
		(start 294.711628 -239.391952)
		(end 294.436292 -239.116616)
		(width 0.18288)
		(layer "In4.Cu")
		(net "M_C_CPU0_SB_DQS_DP<9>")
	)
	(segment
		(start 297.986196 -238.266478)
		(end 297.126914 -239.12576)
		(width 0.18288)
		(layer "In4.Cu")
		(net "M_C_CPU0_SB_DQS_DP<9>")
	)
	(segment
		(start 337.227164 -240.351564)
		(end 337.212432 -240.342928)
		(width 0.088646)
		(layer "In4.Cu")
		(net "M_C_CPU0_SB_DQS_DP<9>")
	)
	(segment
		(start 335.347564 -240.351564)
		(end 335.332832 -240.342928)
		(width 0.088646)
		(layer "In4.Cu")
		(net "M_C_CPU0_SB_DQS_DP<9>")
	)
	(segment
		(start 309.636414 -238.496856)
		(end 308.718458 -237.5789)
		(width 0.18288)
		(layer "In4.Cu")
		(net "M_C_CPU0_SB_DQS_DP<9>")
	)
	(segment
		(start 283.440632 -238.266478)
		(end 282.84297 -238.266478)
		(width 0.18288)
		(layer "In4.Cu")
		(net "M_C_CPU0_SB_DQS_DP<9>")
	)
	(segment
		(start 336.843624 -240.339372)
		(end 336.841592 -240.340642)
		(width 0.088646)
		(layer "In4.Cu")
		(net "M_C_CPU0_SB_DQS_DP<9>")
	)
	(segment
		(start 337.212432 -240.342928)
		(end 337.212432 -240.342674)
		(width 0.088646)
		(layer "In4.Cu")
		(net "M_C_CPU0_SB_DQS_DP<9>")
	)
	(segment
		(start 282.84297 -238.266478)
		(end 282.126182 -237.54969)
		(width 0.18288)
		(layer "In4.Cu")
		(net "M_C_CPU0_SB_DQS_DP<9>")
	)
	(segment
		(start 332.57236 -241.18062)
		(end 332.55839 -241.191542)
		(width 0.088646)
		(layer "In4.Cu")
		(net "M_C_CPU0_SB_DQS_DP<9>")
	)
	(segment
		(start 332.530704 -241.21618)
		(end 332.220824 -241.525806)
		(width 0.088646)
		(layer "In4.Cu")
		(net "M_C_CPU0_SB_DQS_DP<9>")
	)
	(segment
		(start 284.192472 -238.541814)
		(end 283.715968 -238.541814)
		(width 0.18288)
		(layer "In4.Cu")
		(net "M_C_CPU0_SB_DQS_DP<9>")
	)
	(segment
		(start 298.53128 -238.266478)
		(end 297.986196 -238.266478)
		(width 0.18288)
		(layer "In4.Cu")
		(net "M_C_CPU0_SB_DQS_DP<9>")
	)
	(segment
		(start 303.964848 -237.5789)
		(end 303.262792 -238.280956)
		(width 0.18288)
		(layer "In4.Cu")
		(net "M_C_CPU0_SB_DQS_DP<9>")
	)
	(segment
		(start 338.151978 -240.342674)
		(end 338.152232 -240.342928)
		(width 0.088646)
		(layer "In4.Cu")
		(net "M_C_CPU0_SB_DQS_DP<9>")
	)
	(segment
		(start 332.608936 -241.156744)
		(end 332.600046 -241.162078)
		(width 0.088646)
		(layer "In4.Cu")
		(net "M_C_CPU0_SB_DQS_DP<9>")
	)
	(segment
		(start 338.926678 -240.222278)
		(end 338.703158 -240.351056)
		(width 0.088646)
		(layer "In4.Cu")
		(net "M_C_CPU0_SB_DQS_DP<9>")
	)
	(segment
		(start 339.344254 -240.226596)
		(end 339.287104 -240.219738)
		(width 0.088646)
		(layer "In4.Cu")
		(net "M_C_CPU0_SB_DQS_DP<9>")
	)
	(segment
		(start 283.715968 -238.541814)
		(end 283.440632 -238.266478)
		(width 0.18288)
		(layer "In4.Cu")
		(net "M_C_CPU0_SB_DQS_DP<9>")
	)
	(segment
		(start 315.606176 -238.877348)
		(end 311.23128 -238.877348)
		(width 0.18288)
		(layer "In4.Cu")
		(net "M_C_CPU0_SB_DQS_DP<9>")
	)
	(segment
		(start 334.770984 -240.667286)
		(end 334.770984 -240.677192)
		(width 0.088646)
		(layer "In4.Cu")
		(net "M_C_CPU0_SB_DQS_DP<9>")
	)
	(segment
		(start 318.314578 -241.58575)
		(end 315.606176 -238.877348)
		(width 0.18288)
		(layer "In4.Cu")
		(net "M_C_CPU0_SB_DQS_DP<9>")
	)
	(segment
		(start 331.037692 -241.58575)
		(end 331.004164 -241.58575)
		(width 0.088646)
		(layer "In4.Cu")
		(net "M_C_CPU0_SB_DQS_DP<9>")
	)
	(arc
		(start 337.212432 -240.342674)
		(mid 337.028478 -240.292579)
		(end 336.843624 -240.339372)
		(width 0.088646)
		(layer "In4.Cu")
		(net "M_C_CPU0_SB_DQS_DP<9>")
	)
	(arc
		(start 338.152232 -240.342928)
		(mid 337.965034 -240.292785)
		(end 337.777836 -240.342928)
		(width 0.088646)
		(layer "In4.Cu")
		(net "M_C_CPU0_SB_DQS_DP<9>")
	)
	(arc
		(start 339.548724 -240.18494)
		(mid 339.449882 -240.22245)
		(end 339.344254 -240.226596)
		(width 0.088646)
		(layer "In4.Cu")
		(net "M_C_CPU0_SB_DQS_DP<9>")
	)
	(arc
		(start 336.272632 -240.342928)
		(mid 336.085434 -240.292785)
		(end 335.898236 -240.342928)
		(width 0.088646)
		(layer "In4.Cu")
		(net "M_C_CPU0_SB_DQS_DP<9>")
	)
	(arc
		(start 334.771238 -240.652554)
		(mid 334.771041 -240.659919)
		(end 334.770984 -240.667286)
		(width 0.088646)
		(layer "In4.Cu")
		(net "M_C_CPU0_SB_DQS_DP<9>")
	)
	(arc
		(start 333.923132 -241.156744)
		(mid 333.735934 -241.106601)
		(end 333.548736 -241.156744)
		(width 0.088646)
		(layer "In4.Cu")
		(net "M_C_CPU0_SB_DQS_DP<9>")
	)
	(arc
		(start 340.31428 -239.853216)
		(mid 340.138259 -239.876053)
		(end 339.97392 -239.943132)
		(width 0.088646)
		(layer "In4.Cu")
		(net "M_C_CPU0_SB_DQS_DP<9>")
	)
	(arc
		(start 335.898236 -240.342928)
		(mid 335.624007 -240.418853)
		(end 335.347564 -240.351564)
		(width 0.088646)
		(layer "In4.Cu")
		(net "M_C_CPU0_SB_DQS_DP<9>")
	)
	(arc
		(start 332.55839 -241.191542)
		(mid 332.544243 -241.20352)
		(end 332.530704 -241.21618)
		(width 0.088646)
		(layer "In4.Cu")
		(net "M_C_CPU0_SB_DQS_DP<9>")
	)
	(arc
		(start 334.770984 -240.677192)
		(mid 334.484109 -241.159277)
		(end 333.923132 -241.156744)
		(width 0.088646)
		(layer "In4.Cu")
		(net "M_C_CPU0_SB_DQS_DP<9>")
	)
	(arc
		(start 338.703158 -240.351056)
		(mid 338.426493 -240.418527)
		(end 338.151978 -240.342674)
		(width 0.088646)
		(layer "In4.Cu")
		(net "M_C_CPU0_SB_DQS_DP<9>")
	)
	(arc
		(start 337.777836 -240.342928)
		(mid 337.503607 -240.418853)
		(end 337.227164 -240.351564)
		(width 0.088646)
		(layer "In4.Cu")
		(net "M_C_CPU0_SB_DQS_DP<9>")
	)
	(arc
		(start 332.983332 -241.156744)
		(mid 332.796134 -241.106601)
		(end 332.608936 -241.156744)
		(width 0.088646)
		(layer "In4.Cu")
		(net "M_C_CPU0_SB_DQS_DP<9>")
	)
	(arc
		(start 332.600046 -241.162078)
		(mid 332.585999 -241.171044)
		(end 332.57236 -241.18062)
		(width 0.088646)
		(layer "In4.Cu")
		(net "M_C_CPU0_SB_DQS_DP<9>")
	)
	(arc
		(start 333.548736 -241.156744)
		(mid 333.266034 -241.23252)
		(end 332.983332 -241.156744)
		(width 0.088646)
		(layer "In4.Cu")
		(net "M_C_CPU0_SB_DQS_DP<9>")
	)
	(arc
		(start 336.83321 -240.345468)
		(mid 336.552575 -240.418636)
		(end 336.272632 -240.342928)
		(width 0.088646)
		(layer "In4.Cu")
		(net "M_C_CPU0_SB_DQS_DP<9>")
	)
	(arc
		(start 335.332832 -240.342928)
		(mid 334.96477 -240.339354)
		(end 334.771238 -240.652554)
		(width 0.088646)
		(layer "In4.Cu")
		(net "M_C_CPU0_SB_DQS_DP<9>")
	)
	(segment
		(start 345.48318 -227.645214)
		(end 345.483434 -227.64496)
		(width 0.20066)
		(layer "F.Cu")
		(net "M_C_CPU0_SB_DQS_DP<8>")
	)
	(segment
		(start 280.054304 -198.591932)
		(end 279.912826 -198.591932)
		(width 0.20066)
		(layer "F.Cu")
		(net "M_C_CPU0_SB_DQS_DP<8>")
	)
	(segment
		(start 283.916882 -199.01662)
		(end 282.811982 -199.01662)
		(width 0.20066)
		(layer "F.Cu")
		(net "M_C_CPU0_SB_DQS_DP<8>")
	)
	(segment
		(start 276.00402 -199.277986)
		(end 275.742654 -199.01662)
		(width 0.20066)
		(layer "F.Cu")
		(net "M_C_CPU0_SB_DQS_DP<8>")
	)
	(segment
		(start 276.760686 -198.855584)
		(end 276.338284 -199.277986)
		(width 0.20066)
		(layer "F.Cu")
		(net "M_C_CPU0_SB_DQS_DP<8>")
	)
	(segment
		(start 281.456384 -199.277986)
		(end 280.820368 -198.853044)
		(width 0.20066)
		(layer "F.Cu")
		(net "M_C_CPU0_SB_DQS_DP<8>")
	)
	(segment
		(start 282.060904 -199.277986)
		(end 281.456384 -199.277986)
		(width 0.20066)
		(layer "F.Cu")
		(net "M_C_CPU0_SB_DQS_DP<8>")
	)
	(segment
		(start 280.315416 -198.853044)
		(end 280.054304 -198.591932)
		(width 0.20066)
		(layer "F.Cu")
		(net "M_C_CPU0_SB_DQS_DP<8>")
	)
	(segment
		(start 277.834598 -198.591678)
		(end 277.593298 -198.591678)
		(width 0.101854)
		(layer "F.Cu")
		(net "M_C_CPU0_SB_DQS_DP<8>")
	)
	(segment
		(start 280.820368 -198.853044)
		(end 280.315416 -198.853044)
		(width 0.20066)
		(layer "F.Cu")
		(net "M_C_CPU0_SB_DQS_DP<8>")
	)
	(segment
		(start 277.593298 -198.591678)
		(end 277.58771 -198.58609)
		(width 0.101854)
		(layer "F.Cu")
		(net "M_C_CPU0_SB_DQS_DP<8>")
	)
	(segment
		(start 279.912572 -198.591678)
		(end 277.834598 -198.591678)
		(width 0.1016)
		(layer "F.Cu")
		(net "M_C_CPU0_SB_DQS_DP<8>")
	)
	(segment
		(start 277.58771 -198.58609)
		(end 277.390352 -198.58609)
		(width 0.20066)
		(layer "F.Cu")
		(net "M_C_CPU0_SB_DQS_DP<8>")
	)
	(segment
		(start 276.338284 -199.277986)
		(end 276.00402 -199.277986)
		(width 0.20066)
		(layer "F.Cu")
		(net "M_C_CPU0_SB_DQS_DP<8>")
	)
	(segment
		(start 282.32227 -199.01662)
		(end 282.060904 -199.277986)
		(width 0.20066)
		(layer "F.Cu")
		(net "M_C_CPU0_SB_DQS_DP<8>")
	)
	(segment
		(start 345.48318 -228.1809)
		(end 345.48318 -227.645214)
		(width 0.20066)
		(layer "F.Cu")
		(net "M_C_CPU0_SB_DQS_DP<8>")
	)
	(segment
		(start 275.742654 -199.01662)
		(end 275.268182 -199.01662)
		(width 0.20066)
		(layer "F.Cu")
		(net "M_C_CPU0_SB_DQS_DP<8>")
	)
	(segment
		(start 279.912826 -198.591932)
		(end 279.912572 -198.591678)
		(width 0.1016)
		(layer "F.Cu")
		(net "M_C_CPU0_SB_DQS_DP<8>")
	)
	(segment
		(start 282.811982 -199.01662)
		(end 282.32227 -199.01662)
		(width 0.20066)
		(layer "F.Cu")
		(net "M_C_CPU0_SB_DQS_DP<8>")
	)
	(segment
		(start 277.120858 -198.855584)
		(end 276.760686 -198.855584)
		(width 0.20066)
		(layer "F.Cu")
		(net "M_C_CPU0_SB_DQS_DP<8>")
	)
	(segment
		(start 277.390352 -198.58609)
		(end 277.120858 -198.855584)
		(width 0.20066)
		(layer "F.Cu")
		(net "M_C_CPU0_SB_DQS_DP<8>")
	)
	(segment
		(start 342.946482 -227.155502)
		(end 342.93175 -227.146866)
		(width 0.088646)
		(layer "In6.Cu")
		(net "M_C_CPU0_SB_DQS_DP<8>")
	)
	(segment
		(start 289.44951 -197.718426)
		(end 289.057588 -197.718426)
		(width 0.18288)
		(layer "In6.Cu")
		(net "M_C_CPU0_SB_DQS_DP<8>")
	)
	(segment
		(start 332.796388 -224.638108)
		(end 332.670912 -224.638108)
		(width 0.088646)
		(layer "In6.Cu")
		(net "M_C_CPU0_SB_DQS_DP<8>")
	)
	(segment
		(start 292.309296 -196.552566)
		(end 291.856414 -197.005194)
		(width 0.18288)
		(layer "In6.Cu")
		(net "M_C_CPU0_SB_DQS_DP<8>")
	)
	(segment
		(start 284.240732 -198.820532)
		(end 284.11297 -198.820532)
		(width 0.18288)
		(layer "In6.Cu")
		(net "M_C_CPU0_SB_DQS_DP<8>")
	)
	(segment
		(start 295.377362 -197.162674)
		(end 295.105582 -196.890894)
		(width 0.18288)
		(layer "In6.Cu")
		(net "M_C_CPU0_SB_DQS_DP<8>")
	)
	(segment
		(start 320.309748 -210.950048)
		(end 317.62319 -204.407262)
		(width 0.18288)
		(layer "In6.Cu")
		(net "M_C_CPU0_SB_DQS_DP<8>")
	)
	(segment
		(start 291.856414 -197.005194)
		(end 290.946078 -197.382384)
		(width 0.18288)
		(layer "In6.Cu")
		(net "M_C_CPU0_SB_DQS_DP<8>")
	)
	(segment
		(start 338.162646 -226.33559)
		(end 338.152232 -226.341686)
		(width 0.088646)
		(layer "In6.Cu")
		(net "M_C_CPU0_SB_DQS_DP<8>")
	)
	(segment
		(start 331.203808 -222.354902)
		(end 330.503022 -222.354902)
		(width 0.088646)
		(layer "In6.Cu")
		(net "M_C_CPU0_SB_DQS_DP<8>")
	)
	(segment
		(start 336.180684 -225.203258)
		(end 336.180684 -225.193352)
		(width 0.088646)
		(layer "In6.Cu")
		(net "M_C_CPU0_SB_DQS_DP<8>")
	)
	(segment
		(start 289.057588 -197.718426)
		(end 288.755582 -198.020432)
		(width 0.18288)
		(layer "In6.Cu")
		(net "M_C_CPU0_SB_DQS_DP<8>")
	)
	(segment
		(start 336.368136 -225.527616)
		(end 336.359246 -225.522536)
		(width 0.088646)
		(layer "In6.Cu")
		(net "M_C_CPU0_SB_DQS_DP<8>")
	)
	(segment
		(start 289.729926 -197.998842)
		(end 289.44951 -197.718426)
		(width 0.18288)
		(layer "In6.Cu")
		(net "M_C_CPU0_SB_DQS_DP<8>")
	)
	(segment
		(start 310.707278 -199.821546)
		(end 309.53964 -199.337676)
		(width 0.18288)
		(layer "In6.Cu")
		(net "M_C_CPU0_SB_DQS_DP<8>")
	)
	(segment
		(start 344.456258 -227.278438)
		(end 344.451432 -227.275898)
		(width 0.088646)
		(layer "In6.Cu")
		(net "M_C_CPU0_SB_DQS_DP<8>")
	)
	(segment
		(start 332.670912 -224.638108)
		(end 331.571092 -223.538288)
		(width 0.088646)
		(layer "In6.Cu")
		(net "M_C_CPU0_SB_DQS_DP<8>")
	)
	(segment
		(start 299.194728 -196.04228)
		(end 298.812712 -196.04228)
		(width 0.18288)
		(layer "In6.Cu")
		(net "M_C_CPU0_SB_DQS_DP<8>")
	)
	(segment
		(start 284.423612 -198.469504)
		(end 284.423612 -198.637652)
		(width 0.18288)
		(layer "In6.Cu")
		(net "M_C_CPU0_SB_DQS_DP<8>")
	)
	(segment
		(start 342.006682 -227.155502)
		(end 341.99195 -227.146866)
		(width 0.088646)
		(layer "In6.Cu")
		(net "M_C_CPU0_SB_DQS_DP<8>")
	)
	(segment
		(start 331.571092 -222.722186)
		(end 331.203808 -222.354902)
		(width 0.088646)
		(layer "In6.Cu")
		(net "M_C_CPU0_SB_DQS_DP<8>")
	)
	(segment
		(start 339.657436 -226.341686)
		(end 339.647022 -226.33559)
		(width 0.088646)
		(layer "In6.Cu")
		(net "M_C_CPU0_SB_DQS_DP<8>")
	)
	(segment
		(start 313.64174 -201.395584)
		(end 312.067702 -199.821546)
		(width 0.18288)
		(layer "In6.Cu")
		(net "M_C_CPU0_SB_DQS_DP<8>")
	)
	(segment
		(start 312.067702 -199.821546)
		(end 310.707278 -199.821546)
		(width 0.18288)
		(layer "In6.Cu")
		(net "M_C_CPU0_SB_DQS_DP<8>")
	)
	(segment
		(start 288.755582 -198.020432)
		(end 288.25952 -198.020432)
		(width 0.18288)
		(layer "In6.Cu")
		(net "M_C_CPU0_SB_DQS_DP<8>")
	)
	(segment
		(start 307.746146 -197.956932)
		(end 307.112416 -197.323202)
		(width 0.18288)
		(layer "In6.Cu")
		(net "M_C_CPU0_SB_DQS_DP<8>")
	)
	(segment
		(start 328.997056 -221.909132)
		(end 328.997056 -219.637356)
		(width 0.18288)
		(layer "In6.Cu")
		(net "M_C_CPU0_SB_DQS_DP<8>")
	)
	(segment
		(start 344.095832 -227.275898)
		(end 343.876122 -227.149406)
		(width 0.088646)
		(layer "In6.Cu")
		(net "M_C_CPU0_SB_DQS_DP<8>")
	)
	(segment
		(start 330.41971 -222.294958)
		(end 329.382882 -222.294958)
		(width 0.18288)
		(layer "In6.Cu")
		(net "M_C_CPU0_SB_DQS_DP<8>")
	)
	(segment
		(start 337.227164 -226.33305)
		(end 337.212432 -226.341686)
		(width 0.088646)
		(layer "In6.Cu")
		(net "M_C_CPU0_SB_DQS_DP<8>")
	)
	(segment
		(start 290.946078 -197.382384)
		(end 290.329874 -197.998842)
		(width 0.18288)
		(layer "In6.Cu")
		(net "M_C_CPU0_SB_DQS_DP<8>")
	)
	(segment
		(start 308.158642 -197.956932)
		(end 307.746146 -197.956932)
		(width 0.18288)
		(layer "In6.Cu")
		(net "M_C_CPU0_SB_DQS_DP<8>")
	)
	(segment
		(start 290.329874 -197.998842)
		(end 289.729926 -197.998842)
		(width 0.18288)
		(layer "In6.Cu")
		(net "M_C_CPU0_SB_DQS_DP<8>")
	)
	(segment
		(start 296.300144 -197.162674)
		(end 295.377362 -197.162674)
		(width 0.18288)
		(layer "In6.Cu")
		(net "M_C_CPU0_SB_DQS_DP<8>")
	)
	(segment
		(start 284.423612 -198.637652)
		(end 284.240732 -198.820532)
		(width 0.18288)
		(layer "In6.Cu")
		(net "M_C_CPU0_SB_DQS_DP<8>")
	)
	(segment
		(start 294.437562 -197.165214)
		(end 293.816786 -197.165214)
		(width 0.18288)
		(layer "In6.Cu")
		(net "M_C_CPU0_SB_DQS_DP<8>")
	)
	(segment
		(start 341.067136 -227.155502)
		(end 341.058246 -227.150422)
		(width 0.088646)
		(layer "In6.Cu")
		(net "M_C_CPU0_SB_DQS_DP<8>")
	)
	(segment
		(start 288.00171 -197.762622)
		(end 285.130494 -197.762622)
		(width 0.18288)
		(layer "In6.Cu")
		(net "M_C_CPU0_SB_DQS_DP<8>")
	)
	(segment
		(start 328.997056 -219.637356)
		(end 320.309748 -210.950048)
		(width 0.18288)
		(layer "In6.Cu")
		(net "M_C_CPU0_SB_DQS_DP<8>")
	)
	(segment
		(start 332.83271 -224.639124)
		(end 332.831948 -224.639124)
		(width 0.088646)
		(layer "In6.Cu")
		(net "M_C_CPU0_SB_DQS_DP<8>")
	)
	(segment
		(start 329.382882 -222.294958)
		(end 328.997056 -221.909132)
		(width 0.18288)
		(layer "In6.Cu")
		(net "M_C_CPU0_SB_DQS_DP<8>")
	)
	(segment
		(start 330.503022 -222.354902)
		(end 330.443078 -222.294958)
		(width 0.088646)
		(layer "In6.Cu")
		(net "M_C_CPU0_SB_DQS_DP<8>")
	)
	(segment
		(start 299.468286 -196.315838)
		(end 299.194728 -196.04228)
		(width 0.18288)
		(layer "In6.Cu")
		(net "M_C_CPU0_SB_DQS_DP<8>")
	)
	(segment
		(start 293.204138 -196.552566)
		(end 292.309296 -196.552566)
		(width 0.18288)
		(layer "In6.Cu")
		(net "M_C_CPU0_SB_DQS_DP<8>")
	)
	(segment
		(start 284.11297 -198.820532)
		(end 283.916882 -199.01662)
		(width 0.18288)
		(layer "In6.Cu")
		(net "M_C_CPU0_SB_DQS_DP<8>")
	)
	(segment
		(start 330.443078 -222.294958)
		(end 330.41971 -222.294958)
		(width 0.088646)
		(layer "In6.Cu")
		(net "M_C_CPU0_SB_DQS_DP<8>")
	)
	(segment
		(start 302.676306 -196.315838)
		(end 299.468286 -196.315838)
		(width 0.18288)
		(layer "In6.Cu")
		(net "M_C_CPU0_SB_DQS_DP<8>")
	)
	(segment
		(start 334.018636 -224.7138)
		(end 334.008222 -224.707704)
		(width 0.088646)
		(layer "In6.Cu")
		(net "M_C_CPU0_SB_DQS_DP<8>")
	)
	(segment
		(start 340.879684 -226.831144)
		(end 340.879684 -226.821238)
		(width 0.088646)
		(layer "In6.Cu")
		(net "M_C_CPU0_SB_DQS_DP<8>")
	)
	(segment
		(start 344.451432 -227.275898)
		(end 344.095832 -227.275898)
		(width 0.088646)
		(layer "In6.Cu")
		(net "M_C_CPU0_SB_DQS_DP<8>")
	)
	(segment
		(start 317.62319 -204.407262)
		(end 314.611512 -201.395584)
		(width 0.18288)
		(layer "In6.Cu")
		(net "M_C_CPU0_SB_DQS_DP<8>")
	)
	(segment
		(start 344.513408 -227.27158)
		(end 344.456258 -227.278438)
		(width 0.088646)
		(layer "In6.Cu")
		(net "M_C_CPU0_SB_DQS_DP<8>")
	)
	(segment
		(start 285.130494 -197.762622)
		(end 284.423612 -198.469504)
		(width 0.18288)
		(layer "In6.Cu")
		(net "M_C_CPU0_SB_DQS_DP<8>")
	)
	(segment
		(start 336.650584 -226.017328)
		(end 336.650584 -225.998786)
		(width 0.088646)
		(layer "In6.Cu")
		(net "M_C_CPU0_SB_DQS_DP<8>")
	)
	(segment
		(start 314.611512 -201.395584)
		(end 313.64174 -201.395584)
		(width 0.18288)
		(layer "In6.Cu")
		(net "M_C_CPU0_SB_DQS_DP<8>")
	)
	(segment
		(start 295.105582 -196.890894)
		(end 294.711882 -196.890894)
		(width 0.18288)
		(layer "In6.Cu")
		(net "M_C_CPU0_SB_DQS_DP<8>")
	)
	(segment
		(start 345.143074 -227.555044)
		(end 344.717878 -227.313236)
		(width 0.088646)
		(layer "In6.Cu")
		(net "M_C_CPU0_SB_DQS_DP<8>")
	)
	(segment
		(start 341.066882 -227.155502)
		(end 341.067136 -227.155502)
		(width 0.088646)
		(layer "In6.Cu")
		(net "M_C_CPU0_SB_DQS_DP<8>")
	)
	(segment
		(start 288.25952 -198.020432)
		(end 288.00171 -197.762622)
		(width 0.18288)
		(layer "In6.Cu")
		(net "M_C_CPU0_SB_DQS_DP<8>")
	)
	(segment
		(start 298.31411 -196.328538)
		(end 296.300144 -197.162674)
		(width 0.18288)
		(layer "In6.Cu")
		(net "M_C_CPU0_SB_DQS_DP<8>")
	)
	(segment
		(start 331.571092 -223.538288)
		(end 331.571092 -222.722186)
		(width 0.088646)
		(layer "In6.Cu")
		(net "M_C_CPU0_SB_DQS_DP<8>")
	)
	(segment
		(start 298.526454 -196.328538)
		(end 298.31411 -196.328538)
		(width 0.18288)
		(layer "In6.Cu")
		(net "M_C_CPU0_SB_DQS_DP<8>")
	)
	(segment
		(start 309.53964 -199.337676)
		(end 308.158642 -197.956932)
		(width 0.18288)
		(layer "In6.Cu")
		(net "M_C_CPU0_SB_DQS_DP<8>")
	)
	(segment
		(start 298.812712 -196.04228)
		(end 298.526454 -196.328538)
		(width 0.18288)
		(layer "In6.Cu")
		(net "M_C_CPU0_SB_DQS_DP<8>")
	)
	(segment
		(start 294.711882 -196.890894)
		(end 294.437562 -197.165214)
		(width 0.18288)
		(layer "In6.Cu")
		(net "M_C_CPU0_SB_DQS_DP<8>")
	)
	(segment
		(start 336.838036 -226.341686)
		(end 336.829146 -226.336606)
		(width 0.088646)
		(layer "In6.Cu")
		(net "M_C_CPU0_SB_DQS_DP<8>")
	)
	(segment
		(start 307.112416 -197.323202)
		(end 303.68367 -197.323202)
		(width 0.18288)
		(layer "In6.Cu")
		(net "M_C_CPU0_SB_DQS_DP<8>")
	)
	(segment
		(start 293.816786 -197.165214)
		(end 293.204138 -196.552566)
		(width 0.18288)
		(layer "In6.Cu")
		(net "M_C_CPU0_SB_DQS_DP<8>")
	)
	(segment
		(start 303.68367 -197.323202)
		(end 302.676306 -196.315838)
		(width 0.18288)
		(layer "In6.Cu")
		(net "M_C_CPU0_SB_DQS_DP<8>")
	)
	(arc
		(start 336.180684 -225.193352)
		(mid 336.102573 -224.916403)
		(end 335.898236 -224.7138)
		(width 0.088646)
		(layer "In6.Cu")
		(net "M_C_CPU0_SB_DQS_DP<8>")
	)
	(arc
		(start 345.483434 -227.64496)
		(mid 345.307413 -227.622123)
		(end 345.143074 -227.555044)
		(width 0.088646)
		(layer "In6.Cu")
		(net "M_C_CPU0_SB_DQS_DP<8>")
	)
	(arc
		(start 332.831948 -224.639124)
		(mid 332.814176 -224.63834)
		(end 332.796388 -224.638108)
		(width 0.088646)
		(layer "In6.Cu")
		(net "M_C_CPU0_SB_DQS_DP<8>")
	)
	(arc
		(start 342.93175 -227.146866)
		(mid 342.655275 -227.079546)
		(end 342.381078 -227.155502)
		(width 0.088646)
		(layer "In6.Cu")
		(net "M_C_CPU0_SB_DQS_DP<8>")
	)
	(arc
		(start 336.829146 -226.336606)
		(mid 336.698232 -226.200246)
		(end 336.650584 -226.017328)
		(width 0.088646)
		(layer "In6.Cu")
		(net "M_C_CPU0_SB_DQS_DP<8>")
	)
	(arc
		(start 337.777836 -226.341686)
		(mid 337.503637 -226.265851)
		(end 337.227164 -226.33305)
		(width 0.088646)
		(layer "In6.Cu")
		(net "M_C_CPU0_SB_DQS_DP<8>")
	)
	(arc
		(start 342.381078 -227.155502)
		(mid 342.19388 -227.205645)
		(end 342.006682 -227.155502)
		(width 0.088646)
		(layer "In6.Cu")
		(net "M_C_CPU0_SB_DQS_DP<8>")
	)
	(arc
		(start 334.958436 -224.7138)
		(mid 334.675734 -224.638024)
		(end 334.393032 -224.7138)
		(width 0.088646)
		(layer "In6.Cu")
		(net "M_C_CPU0_SB_DQS_DP<8>")
	)
	(arc
		(start 335.898236 -224.7138)
		(mid 335.615534 -224.638024)
		(end 335.332832 -224.7138)
		(width 0.088646)
		(layer "In6.Cu")
		(net "M_C_CPU0_SB_DQS_DP<8>")
	)
	(arc
		(start 340.879684 -226.821238)
		(mid 340.801573 -226.544289)
		(end 340.597236 -226.341686)
		(width 0.088646)
		(layer "In6.Cu")
		(net "M_C_CPU0_SB_DQS_DP<8>")
	)
	(arc
		(start 340.597236 -226.341686)
		(mid 340.314534 -226.26591)
		(end 340.031832 -226.341686)
		(width 0.088646)
		(layer "In6.Cu")
		(net "M_C_CPU0_SB_DQS_DP<8>")
	)
	(arc
		(start 341.058246 -227.150422)
		(mid 340.927332 -227.014062)
		(end 340.879684 -226.831144)
		(width 0.088646)
		(layer "In6.Cu")
		(net "M_C_CPU0_SB_DQS_DP<8>")
	)
	(arc
		(start 333.452978 -224.7138)
		(mid 333.26578 -224.763943)
		(end 333.078582 -224.7138)
		(width 0.088646)
		(layer "In6.Cu")
		(net "M_C_CPU0_SB_DQS_DP<8>")
	)
	(arc
		(start 335.332832 -224.7138)
		(mid 335.145634 -224.763943)
		(end 334.958436 -224.7138)
		(width 0.088646)
		(layer "In6.Cu")
		(net "M_C_CPU0_SB_DQS_DP<8>")
	)
	(arc
		(start 343.876122 -227.149406)
		(mid 343.59769 -227.07956)
		(end 343.320878 -227.155502)
		(width 0.088646)
		(layer "In6.Cu")
		(net "M_C_CPU0_SB_DQS_DP<8>")
	)
	(arc
		(start 333.078582 -224.7138)
		(mid 332.959951 -224.66228)
		(end 332.83271 -224.639124)
		(width 0.088646)
		(layer "In6.Cu")
		(net "M_C_CPU0_SB_DQS_DP<8>")
	)
	(arc
		(start 337.212432 -226.341686)
		(mid 337.025234 -226.391829)
		(end 336.838036 -226.341686)
		(width 0.088646)
		(layer "In6.Cu")
		(net "M_C_CPU0_SB_DQS_DP<8>")
	)
	(arc
		(start 336.359246 -225.522536)
		(mid 336.228332 -225.386176)
		(end 336.180684 -225.203258)
		(width 0.088646)
		(layer "In6.Cu")
		(net "M_C_CPU0_SB_DQS_DP<8>")
	)
	(arc
		(start 340.031832 -226.341686)
		(mid 339.844634 -226.391829)
		(end 339.657436 -226.341686)
		(width 0.088646)
		(layer "In6.Cu")
		(net "M_C_CPU0_SB_DQS_DP<8>")
	)
	(arc
		(start 341.441278 -227.155502)
		(mid 341.25408 -227.205645)
		(end 341.066882 -227.155502)
		(width 0.088646)
		(layer "In6.Cu")
		(net "M_C_CPU0_SB_DQS_DP<8>")
	)
	(arc
		(start 338.152232 -226.341686)
		(mid 337.965034 -226.391829)
		(end 337.777836 -226.341686)
		(width 0.088646)
		(layer "In6.Cu")
		(net "M_C_CPU0_SB_DQS_DP<8>")
	)
	(arc
		(start 338.717382 -226.341686)
		(mid 338.440823 -226.265943)
		(end 338.162646 -226.33559)
		(width 0.088646)
		(layer "In6.Cu")
		(net "M_C_CPU0_SB_DQS_DP<8>")
	)
	(arc
		(start 339.091778 -226.341686)
		(mid 338.90458 -226.391829)
		(end 338.717382 -226.341686)
		(width 0.088646)
		(layer "In6.Cu")
		(net "M_C_CPU0_SB_DQS_DP<8>")
	)
	(arc
		(start 339.647022 -226.33559)
		(mid 339.36859 -226.265744)
		(end 339.091778 -226.341686)
		(width 0.088646)
		(layer "In6.Cu")
		(net "M_C_CPU0_SB_DQS_DP<8>")
	)
	(arc
		(start 336.650584 -225.998786)
		(mid 336.570422 -225.726597)
		(end 336.368136 -225.527616)
		(width 0.088646)
		(layer "In6.Cu")
		(net "M_C_CPU0_SB_DQS_DP<8>")
	)
	(arc
		(start 343.320878 -227.155502)
		(mid 343.13368 -227.205645)
		(end 342.946482 -227.155502)
		(width 0.088646)
		(layer "In6.Cu")
		(net "M_C_CPU0_SB_DQS_DP<8>")
	)
	(arc
		(start 344.717878 -227.313236)
		(mid 344.619036 -227.275726)
		(end 344.513408 -227.27158)
		(width 0.088646)
		(layer "In6.Cu")
		(net "M_C_CPU0_SB_DQS_DP<8>")
	)
	(arc
		(start 334.393032 -224.7138)
		(mid 334.205834 -224.763943)
		(end 334.018636 -224.7138)
		(width 0.088646)
		(layer "In6.Cu")
		(net "M_C_CPU0_SB_DQS_DP<8>")
	)
	(arc
		(start 334.008222 -224.707704)
		(mid 333.72979 -224.637858)
		(end 333.452978 -224.7138)
		(width 0.088646)
		(layer "In6.Cu")
		(net "M_C_CPU0_SB_DQS_DP<8>")
	)
	(arc
		(start 341.99195 -227.146866)
		(mid 341.715475 -227.079546)
		(end 341.441278 -227.155502)
		(width 0.088646)
		(layer "In6.Cu")
		(net "M_C_CPU0_SB_DQS_DP<8>")
	)
	(segment
		(start 342.19388 -230.622348)
		(end 342.19388 -230.086662)
		(width 0.20066)
		(layer "F.Cu")
		(net "M_C_CPU0_SB_DQS_DP<7>")
	)
	(segment
		(start 281.456384 -208.62798)
		(end 280.820368 -208.203038)
		(width 0.20066)
		(layer "F.Cu")
		(net "M_C_CPU0_SB_DQS_DP<7>")
	)
	(segment
		(start 282.32227 -208.366614)
		(end 282.060904 -208.62798)
		(width 0.20066)
		(layer "F.Cu")
		(net "M_C_CPU0_SB_DQS_DP<7>")
	)
	(segment
		(start 276.00402 -208.62798)
		(end 275.742654 -208.366614)
		(width 0.20066)
		(layer "F.Cu")
		(net "M_C_CPU0_SB_DQS_DP<7>")
	)
	(segment
		(start 276.338284 -208.62798)
		(end 276.00402 -208.62798)
		(width 0.20066)
		(layer "F.Cu")
		(net "M_C_CPU0_SB_DQS_DP<7>")
	)
	(segment
		(start 342.194134 -230.622602)
		(end 342.19388 -230.622348)
		(width 0.20066)
		(layer "F.Cu")
		(net "M_C_CPU0_SB_DQS_DP<7>")
	)
	(segment
		(start 283.916882 -208.366614)
		(end 282.811982 -208.366614)
		(width 0.20066)
		(layer "F.Cu")
		(net "M_C_CPU0_SB_DQS_DP<7>")
	)
	(segment
		(start 276.760686 -208.205578)
		(end 276.338284 -208.62798)
		(width 0.20066)
		(layer "F.Cu")
		(net "M_C_CPU0_SB_DQS_DP<7>")
	)
	(segment
		(start 279.912826 -207.941926)
		(end 279.912572 -207.941672)
		(width 0.1016)
		(layer "F.Cu")
		(net "M_C_CPU0_SB_DQS_DP<7>")
	)
	(segment
		(start 277.593298 -207.941672)
		(end 277.58771 -207.936084)
		(width 0.101854)
		(layer "F.Cu")
		(net "M_C_CPU0_SB_DQS_DP<7>")
	)
	(segment
		(start 279.912572 -207.941672)
		(end 277.834598 -207.941672)
		(width 0.1016)
		(layer "F.Cu")
		(net "M_C_CPU0_SB_DQS_DP<7>")
	)
	(segment
		(start 282.060904 -208.62798)
		(end 281.456384 -208.62798)
		(width 0.20066)
		(layer "F.Cu")
		(net "M_C_CPU0_SB_DQS_DP<7>")
	)
	(segment
		(start 282.811982 -208.366614)
		(end 282.32227 -208.366614)
		(width 0.20066)
		(layer "F.Cu")
		(net "M_C_CPU0_SB_DQS_DP<7>")
	)
	(segment
		(start 280.820368 -208.203038)
		(end 280.315416 -208.203038)
		(width 0.20066)
		(layer "F.Cu")
		(net "M_C_CPU0_SB_DQS_DP<7>")
	)
	(segment
		(start 277.120858 -208.205578)
		(end 276.760686 -208.205578)
		(width 0.20066)
		(layer "F.Cu")
		(net "M_C_CPU0_SB_DQS_DP<7>")
	)
	(segment
		(start 280.054304 -207.941926)
		(end 279.912826 -207.941926)
		(width 0.20066)
		(layer "F.Cu")
		(net "M_C_CPU0_SB_DQS_DP<7>")
	)
	(segment
		(start 277.58771 -207.936084)
		(end 277.390352 -207.936084)
		(width 0.20066)
		(layer "F.Cu")
		(net "M_C_CPU0_SB_DQS_DP<7>")
	)
	(segment
		(start 280.315416 -208.203038)
		(end 280.054304 -207.941926)
		(width 0.20066)
		(layer "F.Cu")
		(net "M_C_CPU0_SB_DQS_DP<7>")
	)
	(segment
		(start 277.834598 -207.941672)
		(end 277.593298 -207.941672)
		(width 0.101854)
		(layer "F.Cu")
		(net "M_C_CPU0_SB_DQS_DP<7>")
	)
	(segment
		(start 277.390352 -207.936084)
		(end 277.120858 -208.205578)
		(width 0.20066)
		(layer "F.Cu")
		(net "M_C_CPU0_SB_DQS_DP<7>")
	)
	(segment
		(start 275.742654 -208.366614)
		(end 275.268182 -208.366614)
		(width 0.20066)
		(layer "F.Cu")
		(net "M_C_CPU0_SB_DQS_DP<7>")
	)
	(segment
		(start 314.287662 -210.714844)
		(end 311.393332 -210.714844)
		(width 0.18288)
		(layer "In4.Cu")
		(net "M_C_CPU0_SB_DQS_DP<7>")
	)
	(segment
		(start 293.77513 -210.733386)
		(end 292.338252 -209.296508)
		(width 0.18288)
		(layer "In4.Cu")
		(net "M_C_CPU0_SB_DQS_DP<7>")
	)
	(segment
		(start 339.657182 -229.597204)
		(end 339.65134 -229.593648)
		(width 0.088646)
		(layer "In4.Cu")
		(net "M_C_CPU0_SB_DQS_DP<7>")
	)
	(segment
		(start 337.777582 -229.597204)
		(end 337.77174 -229.593648)
		(width 0.088646)
		(layer "In4.Cu")
		(net "M_C_CPU0_SB_DQS_DP<7>")
	)
	(segment
		(start 331.317092 -228.639116)
		(end 331.090778 -228.412802)
		(width 0.088646)
		(layer "In4.Cu")
		(net "M_C_CPU0_SB_DQS_DP<7>")
	)
	(segment
		(start 338.717382 -229.597204)
		(end 338.71154 -229.593648)
		(width 0.088646)
		(layer "In4.Cu")
		(net "M_C_CPU0_SB_DQS_DP<7>")
	)
	(segment
		(start 284.72892 -208.628234)
		(end 284.178502 -208.628234)
		(width 0.18288)
		(layer "In4.Cu")
		(net "M_C_CPU0_SB_DQS_DP<7>")
	)
	(segment
		(start 295.075864 -210.491832)
		(end 294.710866 -210.491832)
		(width 0.18288)
		(layer "In4.Cu")
		(net "M_C_CPU0_SB_DQS_DP<7>")
	)
	(segment
		(start 337.783424 -229.600506)
		(end 337.777582 -229.597204)
		(width 0.088646)
		(layer "In4.Cu")
		(net "M_C_CPU0_SB_DQS_DP<7>")
	)
	(segment
		(start 339.663024 -229.600506)
		(end 339.657182 -229.597204)
		(width 0.088646)
		(layer "In4.Cu")
		(net "M_C_CPU0_SB_DQS_DP<7>")
	)
	(segment
		(start 298.539916 -209.914236)
		(end 297.79849 -209.914236)
		(width 0.18288)
		(layer "In4.Cu")
		(net "M_C_CPU0_SB_DQS_DP<7>")
	)
	(segment
		(start 297.79849 -209.914236)
		(end 296.926 -210.786726)
		(width 0.18288)
		(layer "In4.Cu")
		(net "M_C_CPU0_SB_DQS_DP<7>")
	)
	(segment
		(start 336.837782 -229.597204)
		(end 336.83321 -229.59441)
		(width 0.088646)
		(layer "In4.Cu")
		(net "M_C_CPU0_SB_DQS_DP<7>")
	)
	(segment
		(start 289.972496 -208.909666)
		(end 285.010352 -208.909666)
		(width 0.18288)
		(layer "In4.Cu")
		(net "M_C_CPU0_SB_DQS_DP<7>")
	)
	(segment
		(start 296.926 -210.786726)
		(end 295.370758 -210.786726)
		(width 0.18288)
		(layer "In4.Cu")
		(net "M_C_CPU0_SB_DQS_DP<7>")
	)
	(segment
		(start 319.661032 -222.030036)
		(end 315.455808 -211.882736)
		(width 0.18288)
		(layer "In4.Cu")
		(net "M_C_CPU0_SB_DQS_DP<7>")
	)
	(segment
		(start 330.671932 -228.353112)
		(end 330.648564 -228.353112)
		(width 0.088646)
		(layer "In4.Cu")
		(net "M_C_CPU0_SB_DQS_DP<7>")
	)
	(segment
		(start 332.326488 -229.64775)
		(end 332.161134 -229.64775)
		(width 0.088646)
		(layer "In4.Cu")
		(net "M_C_CPU0_SB_DQS_DP<7>")
	)
	(segment
		(start 333.467964 -229.588568)
		(end 333.453232 -229.597204)
		(width 0.088646)
		(layer "In4.Cu")
		(net "M_C_CPU0_SB_DQS_DP<7>")
	)
	(segment
		(start 330.731622 -228.412802)
		(end 330.671932 -228.353112)
		(width 0.088646)
		(layer "In4.Cu")
		(net "M_C_CPU0_SB_DQS_DP<7>")
	)
	(segment
		(start 332.161134 -229.64775)
		(end 331.317092 -228.803708)
		(width 0.088646)
		(layer "In4.Cu")
		(net "M_C_CPU0_SB_DQS_DP<7>")
	)
	(segment
		(start 335.347564 -229.588568)
		(end 335.332832 -229.597204)
		(width 0.088646)
		(layer "In4.Cu")
		(net "M_C_CPU0_SB_DQS_DP<7>")
	)
	(segment
		(start 338.723224 -229.600506)
		(end 338.717382 -229.597204)
		(width 0.088646)
		(layer "In4.Cu")
		(net "M_C_CPU0_SB_DQS_DP<7>")
	)
	(segment
		(start 285.010352 -208.909666)
		(end 284.72892 -208.628234)
		(width 0.18288)
		(layer "In4.Cu")
		(net "M_C_CPU0_SB_DQS_DP<7>")
	)
	(segment
		(start 336.843624 -229.600506)
		(end 336.837782 -229.597204)
		(width 0.088646)
		(layer "In4.Cu")
		(net "M_C_CPU0_SB_DQS_DP<7>")
	)
	(segment
		(start 299.48505 -209.91322)
		(end 299.213524 -209.641694)
		(width 0.18288)
		(layer "In4.Cu")
		(net "M_C_CPU0_SB_DQS_DP<7>")
	)
	(segment
		(start 332.513432 -229.597204)
		(end 332.513178 -229.597458)
		(width 0.088646)
		(layer "In4.Cu")
		(net "M_C_CPU0_SB_DQS_DP<7>")
	)
	(segment
		(start 342.19388 -230.086662)
		(end 341.880952 -230.086662)
		(width 0.088646)
		(layer "In4.Cu")
		(net "M_C_CPU0_SB_DQS_DP<7>")
	)
	(segment
		(start 292.338252 -209.296508)
		(end 290.359338 -209.296508)
		(width 0.18288)
		(layer "In4.Cu")
		(net "M_C_CPU0_SB_DQS_DP<7>")
	)
	(segment
		(start 315.455808 -211.882736)
		(end 314.287662 -210.714844)
		(width 0.18288)
		(layer "In4.Cu")
		(net "M_C_CPU0_SB_DQS_DP<7>")
	)
	(segment
		(start 299.213524 -209.641694)
		(end 298.812458 -209.641694)
		(width 0.18288)
		(layer "In4.Cu")
		(net "M_C_CPU0_SB_DQS_DP<7>")
	)
	(segment
		(start 341.880952 -230.086662)
		(end 341.815674 -230.021384)
		(width 0.088646)
		(layer "In4.Cu")
		(net "M_C_CPU0_SB_DQS_DP<7>")
	)
	(segment
		(start 330.648564 -228.353112)
		(end 325.983854 -228.353112)
		(width 0.18288)
		(layer "In4.Cu")
		(net "M_C_CPU0_SB_DQS_DP<7>")
	)
	(segment
		(start 309.999126 -209.320638)
		(end 303.650396 -209.320638)
		(width 0.18288)
		(layer "In4.Cu")
		(net "M_C_CPU0_SB_DQS_DP<7>")
	)
	(segment
		(start 290.359338 -209.296508)
		(end 289.972496 -208.909666)
		(width 0.18288)
		(layer "In4.Cu")
		(net "M_C_CPU0_SB_DQS_DP<7>")
	)
	(segment
		(start 331.317092 -228.803708)
		(end 331.317092 -228.639116)
		(width 0.088646)
		(layer "In4.Cu")
		(net "M_C_CPU0_SB_DQS_DP<7>")
	)
	(segment
		(start 331.090778 -228.412802)
		(end 330.731622 -228.412802)
		(width 0.088646)
		(layer "In4.Cu")
		(net "M_C_CPU0_SB_DQS_DP<7>")
	)
	(segment
		(start 332.528164 -229.588568)
		(end 332.513432 -229.597204)
		(width 0.088646)
		(layer "In4.Cu")
		(net "M_C_CPU0_SB_DQS_DP<7>")
	)
	(segment
		(start 295.370758 -210.786726)
		(end 295.075864 -210.491832)
		(width 0.18288)
		(layer "In4.Cu")
		(net "M_C_CPU0_SB_DQS_DP<7>")
	)
	(segment
		(start 298.812458 -209.641694)
		(end 298.539916 -209.914236)
		(width 0.18288)
		(layer "In4.Cu")
		(net "M_C_CPU0_SB_DQS_DP<7>")
	)
	(segment
		(start 284.178502 -208.628234)
		(end 283.916882 -208.366614)
		(width 0.18288)
		(layer "In4.Cu")
		(net "M_C_CPU0_SB_DQS_DP<7>")
	)
	(segment
		(start 303.057814 -209.91322)
		(end 299.48505 -209.91322)
		(width 0.18288)
		(layer "In4.Cu")
		(net "M_C_CPU0_SB_DQS_DP<7>")
	)
	(segment
		(start 334.407764 -229.588568)
		(end 334.393032 -229.597204)
		(width 0.088646)
		(layer "In4.Cu")
		(net "M_C_CPU0_SB_DQS_DP<7>")
	)
	(segment
		(start 294.710866 -210.491832)
		(end 294.469312 -210.733386)
		(width 0.18288)
		(layer "In4.Cu")
		(net "M_C_CPU0_SB_DQS_DP<7>")
	)
	(segment
		(start 340.046564 -229.588568)
		(end 340.031832 -229.597204)
		(width 0.088646)
		(layer "In4.Cu")
		(net "M_C_CPU0_SB_DQS_DP<7>")
	)
	(segment
		(start 294.469312 -210.733386)
		(end 293.77513 -210.733386)
		(width 0.18288)
		(layer "In4.Cu")
		(net "M_C_CPU0_SB_DQS_DP<7>")
	)
	(segment
		(start 325.983854 -228.353112)
		(end 319.661032 -222.030036)
		(width 0.18288)
		(layer "In4.Cu")
		(net "M_C_CPU0_SB_DQS_DP<7>")
	)
	(segment
		(start 340.986364 -229.588568)
		(end 340.971632 -229.597204)
		(width 0.088646)
		(layer "In4.Cu")
		(net "M_C_CPU0_SB_DQS_DP<7>")
	)
	(segment
		(start 311.393332 -210.714844)
		(end 309.999126 -209.320638)
		(width 0.18288)
		(layer "In4.Cu")
		(net "M_C_CPU0_SB_DQS_DP<7>")
	)
	(segment
		(start 303.650396 -209.320638)
		(end 303.057814 -209.91322)
		(width 0.18288)
		(layer "In4.Cu")
		(net "M_C_CPU0_SB_DQS_DP<7>")
	)
	(arc
		(start 337.77174 -229.593648)
		(mid 337.491605 -229.521365)
		(end 337.212432 -229.597204)
		(width 0.088646)
		(layer "In4.Cu")
		(net "M_C_CPU0_SB_DQS_DP<7>")
	)
	(arc
		(start 335.898236 -229.597204)
		(mid 335.624037 -229.521369)
		(end 335.347564 -229.588568)
		(width 0.088646)
		(layer "In4.Cu")
		(net "M_C_CPU0_SB_DQS_DP<7>")
	)
	(arc
		(start 334.018636 -229.597204)
		(mid 333.744437 -229.521369)
		(end 333.467964 -229.588568)
		(width 0.088646)
		(layer "In4.Cu")
		(net "M_C_CPU0_SB_DQS_DP<7>")
	)
	(arc
		(start 341.815674 -230.021384)
		(mid 341.814376 -230.01083)
		(end 341.81288 -230.000302)
		(width 0.088646)
		(layer "In4.Cu")
		(net "M_C_CPU0_SB_DQS_DP<7>")
	)
	(arc
		(start 341.81288 -230.000302)
		(mid 341.720758 -229.767402)
		(end 341.537036 -229.597204)
		(width 0.088646)
		(layer "In4.Cu")
		(net "M_C_CPU0_SB_DQS_DP<7>")
	)
	(arc
		(start 340.031832 -229.597204)
		(mid 339.847878 -229.647333)
		(end 339.663024 -229.600506)
		(width 0.088646)
		(layer "In4.Cu")
		(net "M_C_CPU0_SB_DQS_DP<7>")
	)
	(arc
		(start 339.092032 -229.597204)
		(mid 338.908078 -229.647333)
		(end 338.723224 -229.600506)
		(width 0.088646)
		(layer "In4.Cu")
		(net "M_C_CPU0_SB_DQS_DP<7>")
	)
	(arc
		(start 340.971632 -229.597204)
		(mid 340.784434 -229.647347)
		(end 340.597236 -229.597204)
		(width 0.088646)
		(layer "In4.Cu")
		(net "M_C_CPU0_SB_DQS_DP<7>")
	)
	(arc
		(start 334.393032 -229.597204)
		(mid 334.205834 -229.647347)
		(end 334.018636 -229.597204)
		(width 0.088646)
		(layer "In4.Cu")
		(net "M_C_CPU0_SB_DQS_DP<7>")
	)
	(arc
		(start 335.332832 -229.597204)
		(mid 335.145634 -229.647347)
		(end 334.958436 -229.597204)
		(width 0.088646)
		(layer "In4.Cu")
		(net "M_C_CPU0_SB_DQS_DP<7>")
	)
	(arc
		(start 333.453232 -229.597204)
		(mid 333.266034 -229.647347)
		(end 333.078836 -229.597204)
		(width 0.088646)
		(layer "In4.Cu")
		(net "M_C_CPU0_SB_DQS_DP<7>")
	)
	(arc
		(start 339.65134 -229.593648)
		(mid 339.371205 -229.521365)
		(end 339.092032 -229.597204)
		(width 0.088646)
		(layer "In4.Cu")
		(net "M_C_CPU0_SB_DQS_DP<7>")
	)
	(arc
		(start 334.958436 -229.597204)
		(mid 334.684237 -229.521369)
		(end 334.407764 -229.588568)
		(width 0.088646)
		(layer "In4.Cu")
		(net "M_C_CPU0_SB_DQS_DP<7>")
	)
	(arc
		(start 340.597236 -229.597204)
		(mid 340.323037 -229.521369)
		(end 340.046564 -229.588568)
		(width 0.088646)
		(layer "In4.Cu")
		(net "M_C_CPU0_SB_DQS_DP<7>")
	)
	(arc
		(start 338.152232 -229.597204)
		(mid 337.968278 -229.647333)
		(end 337.783424 -229.600506)
		(width 0.088646)
		(layer "In4.Cu")
		(net "M_C_CPU0_SB_DQS_DP<7>")
	)
	(arc
		(start 336.83321 -229.59441)
		(mid 336.552546 -229.521402)
		(end 336.272632 -229.597204)
		(width 0.088646)
		(layer "In4.Cu")
		(net "M_C_CPU0_SB_DQS_DP<7>")
	)
	(arc
		(start 333.078836 -229.597204)
		(mid 332.804637 -229.521369)
		(end 332.528164 -229.588568)
		(width 0.088646)
		(layer "In4.Cu")
		(net "M_C_CPU0_SB_DQS_DP<7>")
	)
	(arc
		(start 341.537036 -229.597204)
		(mid 341.262837 -229.521369)
		(end 340.986364 -229.588568)
		(width 0.088646)
		(layer "In4.Cu")
		(net "M_C_CPU0_SB_DQS_DP<7>")
	)
	(arc
		(start 336.272632 -229.597204)
		(mid 336.085434 -229.647347)
		(end 335.898236 -229.597204)
		(width 0.088646)
		(layer "In4.Cu")
		(net "M_C_CPU0_SB_DQS_DP<7>")
	)
	(arc
		(start 337.212432 -229.597204)
		(mid 337.028478 -229.647333)
		(end 336.843624 -229.600506)
		(width 0.088646)
		(layer "In4.Cu")
		(net "M_C_CPU0_SB_DQS_DP<7>")
	)
	(arc
		(start 332.513178 -229.597458)
		(mid 332.423132 -229.634844)
		(end 332.326488 -229.64775)
		(width 0.088646)
		(layer "In4.Cu")
		(net "M_C_CPU0_SB_DQS_DP<7>")
	)
	(arc
		(start 338.71154 -229.593648)
		(mid 338.431405 -229.521365)
		(end 338.152232 -229.597204)
		(width 0.088646)
		(layer "In4.Cu")
		(net "M_C_CPU0_SB_DQS_DP<7>")
	)
	(segment
		(start 345.48318 -237.947454)
		(end 345.483434 -237.9472)
		(width 0.20066)
		(layer "F.Cu")
		(net "M_C_CPU0_SB_DQS_DP<6>")
	)
	(segment
		(start 277.120858 -217.555572)
		(end 276.760686 -217.555572)
		(width 0.20066)
		(layer "F.Cu")
		(net "M_C_CPU0_SB_DQS_DP<6>")
	)
	(segment
		(start 276.00402 -217.977974)
		(end 275.742654 -217.716608)
		(width 0.20066)
		(layer "F.Cu")
		(net "M_C_CPU0_SB_DQS_DP<6>")
	)
	(segment
		(start 277.390352 -217.286078)
		(end 277.120858 -217.555572)
		(width 0.20066)
		(layer "F.Cu")
		(net "M_C_CPU0_SB_DQS_DP<6>")
	)
	(segment
		(start 279.912572 -217.291666)
		(end 277.834598 -217.291666)
		(width 0.1016)
		(layer "F.Cu")
		(net "M_C_CPU0_SB_DQS_DP<6>")
	)
	(segment
		(start 277.593298 -217.291666)
		(end 277.58771 -217.286078)
		(width 0.101854)
		(layer "F.Cu")
		(net "M_C_CPU0_SB_DQS_DP<6>")
	)
	(segment
		(start 277.58771 -217.286078)
		(end 277.390352 -217.286078)
		(width 0.20066)
		(layer "F.Cu")
		(net "M_C_CPU0_SB_DQS_DP<6>")
	)
	(segment
		(start 275.742654 -217.716608)
		(end 275.268182 -217.716608)
		(width 0.20066)
		(layer "F.Cu")
		(net "M_C_CPU0_SB_DQS_DP<6>")
	)
	(segment
		(start 279.912826 -217.29192)
		(end 279.912572 -217.291666)
		(width 0.1016)
		(layer "F.Cu")
		(net "M_C_CPU0_SB_DQS_DP<6>")
	)
	(segment
		(start 282.32227 -217.716608)
		(end 282.060904 -217.977974)
		(width 0.20066)
		(layer "F.Cu")
		(net "M_C_CPU0_SB_DQS_DP<6>")
	)
	(segment
		(start 282.060904 -217.977974)
		(end 281.456384 -217.977974)
		(width 0.20066)
		(layer "F.Cu")
		(net "M_C_CPU0_SB_DQS_DP<6>")
	)
	(segment
		(start 280.820368 -217.553032)
		(end 280.315416 -217.553032)
		(width 0.20066)
		(layer "F.Cu")
		(net "M_C_CPU0_SB_DQS_DP<6>")
	)
	(segment
		(start 283.916882 -217.716608)
		(end 282.811982 -217.716608)
		(width 0.20066)
		(layer "F.Cu")
		(net "M_C_CPU0_SB_DQS_DP<6>")
	)
	(segment
		(start 277.834598 -217.291666)
		(end 277.593298 -217.291666)
		(width 0.101854)
		(layer "F.Cu")
		(net "M_C_CPU0_SB_DQS_DP<6>")
	)
	(segment
		(start 276.760686 -217.555572)
		(end 276.338284 -217.977974)
		(width 0.20066)
		(layer "F.Cu")
		(net "M_C_CPU0_SB_DQS_DP<6>")
	)
	(segment
		(start 345.483434 -237.9472)
		(end 345.483434 -237.411514)
		(width 0.20066)
		(layer "F.Cu")
		(net "M_C_CPU0_SB_DQS_DP<6>")
	)
	(segment
		(start 282.811982 -217.716608)
		(end 282.32227 -217.716608)
		(width 0.20066)
		(layer "F.Cu")
		(net "M_C_CPU0_SB_DQS_DP<6>")
	)
	(segment
		(start 281.456384 -217.977974)
		(end 280.820368 -217.553032)
		(width 0.20066)
		(layer "F.Cu")
		(net "M_C_CPU0_SB_DQS_DP<6>")
	)
	(segment
		(start 276.338284 -217.977974)
		(end 276.00402 -217.977974)
		(width 0.20066)
		(layer "F.Cu")
		(net "M_C_CPU0_SB_DQS_DP<6>")
	)
	(segment
		(start 280.054304 -217.29192)
		(end 279.912826 -217.29192)
		(width 0.20066)
		(layer "F.Cu")
		(net "M_C_CPU0_SB_DQS_DP<6>")
	)
	(segment
		(start 280.315416 -217.553032)
		(end 280.054304 -217.29192)
		(width 0.20066)
		(layer "F.Cu")
		(net "M_C_CPU0_SB_DQS_DP<6>")
	)
	(segment
		(start 291.755576 -220.0148)
		(end 291.051742 -220.0148)
		(width 0.18288)
		(layer "In6.Cu")
		(net "M_C_CPU0_SB_DQS_DP<6>")
	)
	(segment
		(start 292.365938 -219.404438)
		(end 291.755576 -220.0148)
		(width 0.18288)
		(layer "In6.Cu")
		(net "M_C_CPU0_SB_DQS_DP<6>")
	)
	(segment
		(start 284.614112 -217.99931)
		(end 284.199584 -217.99931)
		(width 0.18288)
		(layer "In6.Cu")
		(net "M_C_CPU0_SB_DQS_DP<6>")
	)
	(segment
		(start 344.832178 -236.925612)
		(end 344.826082 -236.922056)
		(width 0.088646)
		(layer "In6.Cu")
		(net "M_C_CPU0_SB_DQS_DP<6>")
	)
	(segment
		(start 339.187282 -236.922056)
		(end 339.17255 -236.91342)
		(width 0.088646)
		(layer "In6.Cu")
		(net "M_C_CPU0_SB_DQS_DP<6>")
	)
	(segment
		(start 284.844236 -218.229434)
		(end 284.614112 -217.99931)
		(width 0.18288)
		(layer "In6.Cu")
		(net "M_C_CPU0_SB_DQS_DP<6>")
	)
	(segment
		(start 345.483434 -237.411514)
		(end 345.170506 -237.411514)
		(width 0.088646)
		(layer "In6.Cu")
		(net "M_C_CPU0_SB_DQS_DP<6>")
	)
	(segment
		(start 295.404794 -220.101922)
		(end 295.144698 -219.841826)
		(width 0.18288)
		(layer "In6.Cu")
		(net "M_C_CPU0_SB_DQS_DP<6>")
	)
	(segment
		(start 337.307682 -236.922056)
		(end 337.297268 -236.91596)
		(width 0.088646)
		(layer "In6.Cu")
		(net "M_C_CPU0_SB_DQS_DP<6>")
	)
	(segment
		(start 284.199584 -217.99931)
		(end 283.916882 -217.716608)
		(width 0.18288)
		(layer "In6.Cu")
		(net "M_C_CPU0_SB_DQS_DP<6>")
	)
	(segment
		(start 343.886282 -236.922056)
		(end 343.87155 -236.91342)
		(width 0.088646)
		(layer "In6.Cu")
		(net "M_C_CPU0_SB_DQS_DP<6>")
	)
	(segment
		(start 316.460378 -225.830892)
		(end 315.023754 -224.396046)
		(width 0.18288)
		(layer "In6.Cu")
		(net "M_C_CPU0_SB_DQS_DP<6>")
	)
	(segment
		(start 334.301084 -236.597952)
		(end 334.301084 -236.588046)
		(width 0.088646)
		(layer "In6.Cu")
		(net "M_C_CPU0_SB_DQS_DP<6>")
	)
	(segment
		(start 341.066882 -236.922056)
		(end 341.05215 -236.91342)
		(width 0.088646)
		(layer "In6.Cu")
		(net "M_C_CPU0_SB_DQS_DP<6>")
	)
	(segment
		(start 345.170506 -237.411514)
		(end 345.104974 -237.345982)
		(width 0.088646)
		(layer "In6.Cu")
		(net "M_C_CPU0_SB_DQS_DP<6>")
	)
	(segment
		(start 338.247482 -236.922056)
		(end 338.23275 -236.91342)
		(width 0.088646)
		(layer "In6.Cu")
		(net "M_C_CPU0_SB_DQS_DP<6>")
	)
	(segment
		(start 298.032932 -220.938598)
		(end 297.196256 -220.101922)
		(width 0.18288)
		(layer "In6.Cu")
		(net "M_C_CPU0_SB_DQS_DP<6>")
	)
	(segment
		(start 295.144698 -219.841826)
		(end 294.643048 -219.841826)
		(width 0.18288)
		(layer "In6.Cu")
		(net "M_C_CPU0_SB_DQS_DP<6>")
	)
	(segment
		(start 331.980794 -235.939584)
		(end 331.980794 -235.57738)
		(width 0.088646)
		(layer "In6.Cu")
		(net "M_C_CPU0_SB_DQS_DP<6>")
	)
	(segment
		(start 342.946482 -236.922056)
		(end 342.936068 -236.91596)
		(width 0.088646)
		(layer "In6.Cu")
		(net "M_C_CPU0_SB_DQS_DP<6>")
	)
	(segment
		(start 294.388794 -220.09608)
		(end 293.843964 -220.09608)
		(width 0.18288)
		(layer "In6.Cu")
		(net "M_C_CPU0_SB_DQS_DP<6>")
	)
	(segment
		(start 344.826082 -236.922056)
		(end 344.81135 -236.91342)
		(width 0.088646)
		(layer "In6.Cu")
		(net "M_C_CPU0_SB_DQS_DP<6>")
	)
	(segment
		(start 333.468218 -236.099858)
		(end 333.453486 -236.108494)
		(width 0.088646)
		(layer "In6.Cu")
		(net "M_C_CPU0_SB_DQS_DP<6>")
	)
	(segment
		(start 298.746418 -220.691202)
		(end 298.499022 -220.938598)
		(width 0.18288)
		(layer "In6.Cu")
		(net "M_C_CPU0_SB_DQS_DP<6>")
	)
	(segment
		(start 288.680906 -218.64574)
		(end 287.677098 -218.229434)
		(width 0.18288)
		(layer "In6.Cu")
		(net "M_C_CPU0_SB_DQS_DP<6>")
	)
	(segment
		(start 291.051742 -220.0148)
		(end 289.682682 -218.64574)
		(width 0.18288)
		(layer "In6.Cu")
		(net "M_C_CPU0_SB_DQS_DP<6>")
	)
	(segment
		(start 298.499022 -220.938598)
		(end 298.032932 -220.938598)
		(width 0.18288)
		(layer "In6.Cu")
		(net "M_C_CPU0_SB_DQS_DP<6>")
	)
	(segment
		(start 332.200504 -236.159294)
		(end 331.980794 -235.939584)
		(width 0.088646)
		(layer "In6.Cu")
		(net "M_C_CPU0_SB_DQS_DP<6>")
	)
	(segment
		(start 310.087264 -221.21241)
		(end 307.693314 -221.21241)
		(width 0.18288)
		(layer "In6.Cu")
		(net "M_C_CPU0_SB_DQS_DP<6>")
	)
	(segment
		(start 297.196256 -220.101922)
		(end 295.404794 -220.101922)
		(width 0.18288)
		(layer "In6.Cu")
		(net "M_C_CPU0_SB_DQS_DP<6>")
	)
	(segment
		(start 316.460378 -228.00056)
		(end 316.460378 -225.830892)
		(width 0.18288)
		(layer "In6.Cu")
		(net "M_C_CPU0_SB_DQS_DP<6>")
	)
	(segment
		(start 335.802732 -236.922056)
		(end 335.79181 -236.928406)
		(width 0.088646)
		(layer "In6.Cu")
		(net "M_C_CPU0_SB_DQS_DP<6>")
	)
	(segment
		(start 334.877664 -236.913674)
		(end 334.862932 -236.92231)
		(width 0.088646)
		(layer "In6.Cu")
		(net "M_C_CPU0_SB_DQS_DP<6>")
	)
	(segment
		(start 313.913266 -224.090992)
		(end 313.628278 -224.37598)
		(width 0.18288)
		(layer "In6.Cu")
		(net "M_C_CPU0_SB_DQS_DP<6>")
	)
	(segment
		(start 322.852542 -234.392724)
		(end 316.460378 -228.00056)
		(width 0.18288)
		(layer "In6.Cu")
		(net "M_C_CPU0_SB_DQS_DP<6>")
	)
	(segment
		(start 312.838592 -224.37598)
		(end 311.513474 -223.050862)
		(width 0.18288)
		(layer "In6.Cu")
		(net "M_C_CPU0_SB_DQS_DP<6>")
	)
	(segment
		(start 299.261784 -220.691202)
		(end 298.746418 -220.691202)
		(width 0.18288)
		(layer "In6.Cu")
		(net "M_C_CPU0_SB_DQS_DP<6>")
	)
	(segment
		(start 299.515022 -220.94444)
		(end 299.261784 -220.691202)
		(width 0.18288)
		(layer "In6.Cu")
		(net "M_C_CPU0_SB_DQS_DP<6>")
	)
	(segment
		(start 332.32598 -236.159294)
		(end 332.200504 -236.159294)
		(width 0.088646)
		(layer "In6.Cu")
		(net "M_C_CPU0_SB_DQS_DP<6>")
	)
	(segment
		(start 331.26934 -234.667552)
		(end 331.054456 -234.452668)
		(width 0.088646)
		(layer "In6.Cu")
		(net "M_C_CPU0_SB_DQS_DP<6>")
	)
	(segment
		(start 315.023754 -224.396046)
		(end 314.568586 -224.396046)
		(width 0.18288)
		(layer "In6.Cu")
		(net "M_C_CPU0_SB_DQS_DP<6>")
	)
	(segment
		(start 287.677098 -218.229434)
		(end 284.844236 -218.229434)
		(width 0.18288)
		(layer "In6.Cu")
		(net "M_C_CPU0_SB_DQS_DP<6>")
	)
	(segment
		(start 342.006936 -236.922056)
		(end 341.996522 -236.91596)
		(width 0.088646)
		(layer "In6.Cu")
		(net "M_C_CPU0_SB_DQS_DP<6>")
	)
	(segment
		(start 331.980794 -235.57738)
		(end 331.26934 -234.865926)
		(width 0.088646)
		(layer "In6.Cu")
		(net "M_C_CPU0_SB_DQS_DP<6>")
	)
	(segment
		(start 331.26934 -234.865926)
		(end 331.26934 -234.667552)
		(width 0.088646)
		(layer "In6.Cu")
		(net "M_C_CPU0_SB_DQS_DP<6>")
	)
	(segment
		(start 289.682682 -218.64574)
		(end 288.680906 -218.64574)
		(width 0.18288)
		(layer "In6.Cu")
		(net "M_C_CPU0_SB_DQS_DP<6>")
	)
	(segment
		(start 314.568586 -224.396046)
		(end 314.263532 -224.090992)
		(width 0.18288)
		(layer "In6.Cu")
		(net "M_C_CPU0_SB_DQS_DP<6>")
	)
	(segment
		(start 330.798932 -234.392724)
		(end 330.775564 -234.392724)
		(width 0.088646)
		(layer "In6.Cu")
		(net "M_C_CPU0_SB_DQS_DP<6>")
	)
	(segment
		(start 306.72913 -220.248226)
		(end 303.59604 -220.248226)
		(width 0.18288)
		(layer "In6.Cu")
		(net "M_C_CPU0_SB_DQS_DP<6>")
	)
	(segment
		(start 302.899826 -220.94444)
		(end 299.515022 -220.94444)
		(width 0.18288)
		(layer "In6.Cu")
		(net "M_C_CPU0_SB_DQS_DP<6>")
	)
	(segment
		(start 311.513474 -223.050862)
		(end 310.888888 -221.544642)
		(width 0.18288)
		(layer "In6.Cu")
		(net "M_C_CPU0_SB_DQS_DP<6>")
	)
	(segment
		(start 293.152322 -219.404438)
		(end 292.365938 -219.404438)
		(width 0.18288)
		(layer "In6.Cu")
		(net "M_C_CPU0_SB_DQS_DP<6>")
	)
	(segment
		(start 303.59604 -220.248226)
		(end 302.899826 -220.94444)
		(width 0.18288)
		(layer "In6.Cu")
		(net "M_C_CPU0_SB_DQS_DP<6>")
	)
	(segment
		(start 331.054456 -234.452668)
		(end 330.858876 -234.452668)
		(width 0.088646)
		(layer "In6.Cu")
		(net "M_C_CPU0_SB_DQS_DP<6>")
	)
	(segment
		(start 307.693314 -221.21241)
		(end 306.72913 -220.248226)
		(width 0.18288)
		(layer "In6.Cu")
		(net "M_C_CPU0_SB_DQS_DP<6>")
	)
	(segment
		(start 314.263532 -224.090992)
		(end 313.913266 -224.090992)
		(width 0.18288)
		(layer "In6.Cu")
		(net "M_C_CPU0_SB_DQS_DP<6>")
	)
	(segment
		(start 330.858876 -234.452668)
		(end 330.798932 -234.392724)
		(width 0.088646)
		(layer "In6.Cu")
		(net "M_C_CPU0_SB_DQS_DP<6>")
	)
	(segment
		(start 330.775564 -234.392724)
		(end 322.852542 -234.392724)
		(width 0.18288)
		(layer "In6.Cu")
		(net "M_C_CPU0_SB_DQS_DP<6>")
	)
	(segment
		(start 293.843964 -220.09608)
		(end 293.152322 -219.404438)
		(width 0.18288)
		(layer "In6.Cu")
		(net "M_C_CPU0_SB_DQS_DP<6>")
	)
	(segment
		(start 313.628278 -224.37598)
		(end 312.838592 -224.37598)
		(width 0.18288)
		(layer "In6.Cu")
		(net "M_C_CPU0_SB_DQS_DP<6>")
	)
	(segment
		(start 294.643048 -219.841826)
		(end 294.388794 -220.09608)
		(width 0.18288)
		(layer "In6.Cu")
		(net "M_C_CPU0_SB_DQS_DP<6>")
	)
	(segment
		(start 310.888888 -221.544642)
		(end 310.087264 -221.21241)
		(width 0.18288)
		(layer "In6.Cu")
		(net "M_C_CPU0_SB_DQS_DP<6>")
	)
	(arc
		(start 345.104974 -237.345982)
		(mid 345.01773 -237.103894)
		(end 344.832178 -236.925612)
		(width 0.088646)
		(layer "In6.Cu")
		(net "M_C_CPU0_SB_DQS_DP<6>")
	)
	(arc
		(start 334.301084 -236.588046)
		(mid 334.021757 -236.110058)
		(end 333.468218 -236.099858)
		(width 0.088646)
		(layer "In6.Cu")
		(net "M_C_CPU0_SB_DQS_DP<6>")
	)
	(arc
		(start 335.428336 -236.92231)
		(mid 335.154137 -236.846475)
		(end 334.877664 -236.913674)
		(width 0.088646)
		(layer "In6.Cu")
		(net "M_C_CPU0_SB_DQS_DP<6>")
	)
	(arc
		(start 335.79181 -236.928406)
		(mid 335.60928 -236.97243)
		(end 335.428336 -236.92231)
		(width 0.088646)
		(layer "In6.Cu")
		(net "M_C_CPU0_SB_DQS_DP<6>")
	)
	(arc
		(start 344.81135 -236.91342)
		(mid 344.534875 -236.8461)
		(end 344.260678 -236.922056)
		(width 0.088646)
		(layer "In6.Cu")
		(net "M_C_CPU0_SB_DQS_DP<6>")
	)
	(arc
		(start 343.320878 -236.922056)
		(mid 343.13368 -236.972233)
		(end 342.946482 -236.922056)
		(width 0.088646)
		(layer "In6.Cu")
		(net "M_C_CPU0_SB_DQS_DP<6>")
	)
	(arc
		(start 340.127082 -236.922056)
		(mid 339.84438 -236.84628)
		(end 339.561678 -236.922056)
		(width 0.088646)
		(layer "In6.Cu")
		(net "M_C_CPU0_SB_DQS_DP<6>")
	)
	(arc
		(start 342.381332 -236.922056)
		(mid 342.194134 -236.972233)
		(end 342.006936 -236.922056)
		(width 0.088646)
		(layer "In6.Cu")
		(net "M_C_CPU0_SB_DQS_DP<6>")
	)
	(arc
		(start 338.23275 -236.91342)
		(mid 337.956275 -236.8461)
		(end 337.682078 -236.922056)
		(width 0.088646)
		(layer "In6.Cu")
		(net "M_C_CPU0_SB_DQS_DP<6>")
	)
	(arc
		(start 334.862932 -236.92231)
		(mid 334.488457 -236.922264)
		(end 334.301084 -236.597952)
		(width 0.088646)
		(layer "In6.Cu")
		(net "M_C_CPU0_SB_DQS_DP<6>")
	)
	(arc
		(start 336.368136 -236.922056)
		(mid 336.085434 -236.84628)
		(end 335.802732 -236.922056)
		(width 0.088646)
		(layer "In6.Cu")
		(net "M_C_CPU0_SB_DQS_DP<6>")
	)
	(arc
		(start 338.621878 -236.922056)
		(mid 338.43468 -236.972233)
		(end 338.247482 -236.922056)
		(width 0.088646)
		(layer "In6.Cu")
		(net "M_C_CPU0_SB_DQS_DP<6>")
	)
	(arc
		(start 342.936068 -236.91596)
		(mid 342.65789 -236.846237)
		(end 342.381332 -236.922056)
		(width 0.088646)
		(layer "In6.Cu")
		(net "M_C_CPU0_SB_DQS_DP<6>")
	)
	(arc
		(start 339.17255 -236.91342)
		(mid 338.896075 -236.8461)
		(end 338.621878 -236.922056)
		(width 0.088646)
		(layer "In6.Cu")
		(net "M_C_CPU0_SB_DQS_DP<6>")
	)
	(arc
		(start 337.682078 -236.922056)
		(mid 337.49488 -236.972233)
		(end 337.307682 -236.922056)
		(width 0.088646)
		(layer "In6.Cu")
		(net "M_C_CPU0_SB_DQS_DP<6>")
	)
	(arc
		(start 341.441278 -236.922056)
		(mid 341.25408 -236.972233)
		(end 341.066882 -236.922056)
		(width 0.088646)
		(layer "In6.Cu")
		(net "M_C_CPU0_SB_DQS_DP<6>")
	)
	(arc
		(start 341.996522 -236.91596)
		(mid 341.71809 -236.846114)
		(end 341.441278 -236.922056)
		(width 0.088646)
		(layer "In6.Cu")
		(net "M_C_CPU0_SB_DQS_DP<6>")
	)
	(arc
		(start 340.501478 -236.922056)
		(mid 340.31428 -236.972233)
		(end 340.127082 -236.922056)
		(width 0.088646)
		(layer "In6.Cu")
		(net "M_C_CPU0_SB_DQS_DP<6>")
	)
	(arc
		(start 336.742532 -236.922056)
		(mid 336.555334 -236.972233)
		(end 336.368136 -236.922056)
		(width 0.088646)
		(layer "In6.Cu")
		(net "M_C_CPU0_SB_DQS_DP<6>")
	)
	(arc
		(start 341.05215 -236.91342)
		(mid 340.775675 -236.8461)
		(end 340.501478 -236.922056)
		(width 0.088646)
		(layer "In6.Cu")
		(net "M_C_CPU0_SB_DQS_DP<6>")
	)
	(arc
		(start 339.561678 -236.922056)
		(mid 339.37448 -236.972233)
		(end 339.187282 -236.922056)
		(width 0.088646)
		(layer "In6.Cu")
		(net "M_C_CPU0_SB_DQS_DP<6>")
	)
	(arc
		(start 332.513178 -236.108494)
		(mid 332.422922 -236.146216)
		(end 332.32598 -236.159294)
		(width 0.088646)
		(layer "In6.Cu")
		(net "M_C_CPU0_SB_DQS_DP<6>")
	)
	(arc
		(start 344.260678 -236.922056)
		(mid 344.07348 -236.972233)
		(end 343.886282 -236.922056)
		(width 0.088646)
		(layer "In6.Cu")
		(net "M_C_CPU0_SB_DQS_DP<6>")
	)
	(arc
		(start 333.07909 -236.108494)
		(mid 332.796134 -236.032591)
		(end 332.513178 -236.108494)
		(width 0.088646)
		(layer "In6.Cu")
		(net "M_C_CPU0_SB_DQS_DP<6>")
	)
	(arc
		(start 333.453486 -236.108494)
		(mid 333.266288 -236.158637)
		(end 333.07909 -236.108494)
		(width 0.088646)
		(layer "In6.Cu")
		(net "M_C_CPU0_SB_DQS_DP<6>")
	)
	(arc
		(start 337.297268 -236.91596)
		(mid 337.01909 -236.846237)
		(end 336.742532 -236.922056)
		(width 0.088646)
		(layer "In6.Cu")
		(net "M_C_CPU0_SB_DQS_DP<6>")
	)
	(arc
		(start 343.87155 -236.91342)
		(mid 343.595075 -236.8461)
		(end 343.320878 -236.922056)
		(width 0.088646)
		(layer "In6.Cu")
		(net "M_C_CPU0_SB_DQS_DP<6>")
	)
	(segment
		(start 275.742654 -227.066602)
		(end 275.268182 -227.066602)
		(width 0.20066)
		(layer "F.Cu")
		(net "M_C_CPU0_SB_DQS_DP<5>")
	)
	(segment
		(start 277.120858 -226.905566)
		(end 276.760686 -226.905566)
		(width 0.20066)
		(layer "F.Cu")
		(net "M_C_CPU0_SB_DQS_DP<5>")
	)
	(segment
		(start 280.820368 -226.903026)
		(end 280.315416 -226.903026)
		(width 0.20066)
		(layer "F.Cu")
		(net "M_C_CPU0_SB_DQS_DP<5>")
	)
	(segment
		(start 280.315416 -226.903026)
		(end 280.054304 -226.641914)
		(width 0.20066)
		(layer "F.Cu")
		(net "M_C_CPU0_SB_DQS_DP<5>")
	)
	(segment
		(start 276.338284 -227.327968)
		(end 276.00402 -227.327968)
		(width 0.20066)
		(layer "F.Cu")
		(net "M_C_CPU0_SB_DQS_DP<5>")
	)
	(segment
		(start 282.32227 -227.066602)
		(end 282.060904 -227.327968)
		(width 0.20066)
		(layer "F.Cu")
		(net "M_C_CPU0_SB_DQS_DP<5>")
	)
	(segment
		(start 282.811982 -227.066602)
		(end 282.32227 -227.066602)
		(width 0.20066)
		(layer "F.Cu")
		(net "M_C_CPU0_SB_DQS_DP<5>")
	)
	(segment
		(start 280.054304 -226.641914)
		(end 279.912826 -226.641914)
		(width 0.20066)
		(layer "F.Cu")
		(net "M_C_CPU0_SB_DQS_DP<5>")
	)
	(segment
		(start 277.834598 -226.64166)
		(end 277.593298 -226.64166)
		(width 0.101854)
		(layer "F.Cu")
		(net "M_C_CPU0_SB_DQS_DP<5>")
	)
	(segment
		(start 282.060904 -227.327968)
		(end 281.456384 -227.327968)
		(width 0.20066)
		(layer "F.Cu")
		(net "M_C_CPU0_SB_DQS_DP<5>")
	)
	(segment
		(start 279.912826 -226.641914)
		(end 279.912572 -226.64166)
		(width 0.1016)
		(layer "F.Cu")
		(net "M_C_CPU0_SB_DQS_DP<5>")
	)
	(segment
		(start 283.916882 -227.066602)
		(end 282.811982 -227.066602)
		(width 0.20066)
		(layer "F.Cu")
		(net "M_C_CPU0_SB_DQS_DP<5>")
	)
	(segment
		(start 277.390352 -226.636072)
		(end 277.120858 -226.905566)
		(width 0.20066)
		(layer "F.Cu")
		(net "M_C_CPU0_SB_DQS_DP<5>")
	)
	(segment
		(start 276.00402 -227.327968)
		(end 275.742654 -227.066602)
		(width 0.20066)
		(layer "F.Cu")
		(net "M_C_CPU0_SB_DQS_DP<5>")
	)
	(segment
		(start 281.456384 -227.327968)
		(end 280.820368 -226.903026)
		(width 0.20066)
		(layer "F.Cu")
		(net "M_C_CPU0_SB_DQS_DP<5>")
	)
	(segment
		(start 345.48318 -242.830858)
		(end 345.483434 -242.294918)
		(width 0.20066)
		(layer "F.Cu")
		(net "M_C_CPU0_SB_DQS_DP<5>")
	)
	(segment
		(start 277.593298 -226.64166)
		(end 277.58771 -226.636072)
		(width 0.101854)
		(layer "F.Cu")
		(net "M_C_CPU0_SB_DQS_DP<5>")
	)
	(segment
		(start 276.760686 -226.905566)
		(end 276.338284 -227.327968)
		(width 0.20066)
		(layer "F.Cu")
		(net "M_C_CPU0_SB_DQS_DP<5>")
	)
	(segment
		(start 279.912572 -226.64166)
		(end 277.834598 -226.64166)
		(width 0.1016)
		(layer "F.Cu")
		(net "M_C_CPU0_SB_DQS_DP<5>")
	)
	(segment
		(start 277.58771 -226.636072)
		(end 277.390352 -226.636072)
		(width 0.20066)
		(layer "F.Cu")
		(net "M_C_CPU0_SB_DQS_DP<5>")
	)
	(segment
		(start 289.136074 -229.699566)
		(end 288.105088 -228.66858)
		(width 0.18288)
		(layer "In6.Cu")
		(net "M_C_CPU0_SB_DQS_DP<5>")
	)
	(segment
		(start 284.823408 -227.507546)
		(end 284.663896 -227.348034)
		(width 0.18288)
		(layer "In6.Cu")
		(net "M_C_CPU0_SB_DQS_DP<5>")
	)
	(segment
		(start 310.7944 -233.638344)
		(end 307.577744 -233.638344)
		(width 0.18288)
		(layer "In6.Cu")
		(net "M_C_CPU0_SB_DQS_DP<5>")
	)
	(segment
		(start 334.877664 -241.796824)
		(end 334.862932 -241.80546)
		(width 0.088646)
		(layer "In6.Cu")
		(net "M_C_CPU0_SB_DQS_DP<5>")
	)
	(segment
		(start 337.307682 -241.80546)
		(end 337.29295 -241.796824)
		(width 0.088646)
		(layer "In6.Cu")
		(net "M_C_CPU0_SB_DQS_DP<5>")
	)
	(segment
		(start 343.886282 -241.80546)
		(end 343.87155 -241.796824)
		(width 0.088646)
		(layer "In6.Cu")
		(net "M_C_CPU0_SB_DQS_DP<5>")
	)
	(segment
		(start 331.052932 -240.308384)
		(end 331.029564 -240.308384)
		(width 0.088646)
		(layer "In6.Cu")
		(net "M_C_CPU0_SB_DQS_DP<5>")
	)
	(segment
		(start 333.562452 -241.813842)
		(end 333.524606 -241.791998)
		(width 0.088646)
		(layer "In6.Cu")
		(net "M_C_CPU0_SB_DQS_DP<5>")
	)
	(segment
		(start 340.127082 -241.80546)
		(end 340.11235 -241.796824)
		(width 0.088646)
		(layer "In6.Cu")
		(net "M_C_CPU0_SB_DQS_DP<5>")
	)
	(segment
		(start 284.198314 -227.348034)
		(end 283.916882 -227.066602)
		(width 0.18288)
		(layer "In6.Cu")
		(net "M_C_CPU0_SB_DQS_DP<5>")
	)
	(segment
		(start 285.89097 -227.507546)
		(end 284.823408 -227.507546)
		(width 0.18288)
		(layer "In6.Cu")
		(net "M_C_CPU0_SB_DQS_DP<5>")
	)
	(segment
		(start 293.894002 -231.14635)
		(end 293.127938 -230.380286)
		(width 0.18288)
		(layer "In6.Cu")
		(net "M_C_CPU0_SB_DQS_DP<5>")
	)
	(segment
		(start 284.663896 -227.348034)
		(end 284.198314 -227.348034)
		(width 0.18288)
		(layer "In6.Cu")
		(net "M_C_CPU0_SB_DQS_DP<5>")
	)
	(segment
		(start 294.426894 -231.14635)
		(end 293.894002 -231.14635)
		(width 0.18288)
		(layer "In6.Cu")
		(net "M_C_CPU0_SB_DQS_DP<5>")
	)
	(segment
		(start 299.565314 -232.024428)
		(end 299.282612 -231.741726)
		(width 0.18288)
		(layer "In6.Cu")
		(net "M_C_CPU0_SB_DQS_DP<5>")
	)
	(segment
		(start 332.556866 -241.606324)
		(end 332.43647 -241.485928)
		(width 0.088646)
		(layer "In6.Cu")
		(net "M_C_CPU0_SB_DQS_DP<5>")
	)
	(segment
		(start 298.003722 -231.996234)
		(end 297.417998 -231.41051)
		(width 0.18288)
		(layer "In6.Cu")
		(net "M_C_CPU0_SB_DQS_DP<5>")
	)
	(segment
		(start 298.78147 -231.741726)
		(end 298.526962 -231.996234)
		(width 0.18288)
		(layer "In6.Cu")
		(net "M_C_CPU0_SB_DQS_DP<5>")
	)
	(segment
		(start 331.422502 -240.368328)
		(end 331.112876 -240.368328)
		(width 0.088646)
		(layer "In6.Cu")
		(net "M_C_CPU0_SB_DQS_DP<5>")
	)
	(segment
		(start 315.443616 -236.021626)
		(end 313.778138 -236.021626)
		(width 0.18288)
		(layer "In6.Cu")
		(net "M_C_CPU0_SB_DQS_DP<5>")
	)
	(segment
		(start 291.883338 -229.699566)
		(end 289.136074 -229.699566)
		(width 0.18288)
		(layer "In6.Cu")
		(net "M_C_CPU0_SB_DQS_DP<5>")
	)
	(segment
		(start 344.832178 -241.809016)
		(end 344.826082 -241.80546)
		(width 0.088646)
		(layer "In6.Cu")
		(net "M_C_CPU0_SB_DQS_DP<5>")
	)
	(segment
		(start 307.577744 -233.638344)
		(end 306.832 -232.8926)
		(width 0.18288)
		(layer "In6.Cu")
		(net "M_C_CPU0_SB_DQS_DP<5>")
	)
	(segment
		(start 299.282612 -231.741726)
		(end 298.78147 -231.741726)
		(width 0.18288)
		(layer "In6.Cu")
		(net "M_C_CPU0_SB_DQS_DP<5>")
	)
	(segment
		(start 339.187282 -241.80546)
		(end 339.17255 -241.796824)
		(width 0.088646)
		(layer "In6.Cu")
		(net "M_C_CPU0_SB_DQS_DP<5>")
	)
	(segment
		(start 345.483434 -242.294918)
		(end 345.170506 -242.294918)
		(width 0.088646)
		(layer "In6.Cu")
		(net "M_C_CPU0_SB_DQS_DP<5>")
	)
	(segment
		(start 288.105088 -228.66858)
		(end 287.052004 -228.66858)
		(width 0.18288)
		(layer "In6.Cu")
		(net "M_C_CPU0_SB_DQS_DP<5>")
	)
	(segment
		(start 295.182544 -230.891842)
		(end 294.681402 -230.891842)
		(width 0.18288)
		(layer "In6.Cu")
		(net "M_C_CPU0_SB_DQS_DP<5>")
	)
	(segment
		(start 319.730374 -240.308384)
		(end 315.443616 -236.021626)
		(width 0.18288)
		(layer "In6.Cu")
		(net "M_C_CPU0_SB_DQS_DP<5>")
	)
	(segment
		(start 296.096944 -231.152192)
		(end 295.442894 -231.152192)
		(width 0.18288)
		(layer "In6.Cu")
		(net "M_C_CPU0_SB_DQS_DP<5>")
	)
	(segment
		(start 331.112876 -240.368328)
		(end 331.052932 -240.308384)
		(width 0.088646)
		(layer "In6.Cu")
		(net "M_C_CPU0_SB_DQS_DP<5>")
	)
	(segment
		(start 332.224126 -241.169952)
		(end 331.422502 -240.368328)
		(width 0.088646)
		(layer "In6.Cu")
		(net "M_C_CPU0_SB_DQS_DP<5>")
	)
	(segment
		(start 331.029564 -240.308384)
		(end 319.730374 -240.308384)
		(width 0.18288)
		(layer "In6.Cu")
		(net "M_C_CPU0_SB_DQS_DP<5>")
	)
	(segment
		(start 313.778138 -236.021626)
		(end 312.538618 -234.782106)
		(width 0.18288)
		(layer "In6.Cu")
		(net "M_C_CPU0_SB_DQS_DP<5>")
	)
	(segment
		(start 306.832 -232.8926)
		(end 303.939194 -232.8926)
		(width 0.18288)
		(layer "In6.Cu")
		(net "M_C_CPU0_SB_DQS_DP<5>")
	)
	(segment
		(start 297.417998 -231.41051)
		(end 296.355262 -231.41051)
		(width 0.18288)
		(layer "In6.Cu")
		(net "M_C_CPU0_SB_DQS_DP<5>")
	)
	(segment
		(start 311.938162 -234.782106)
		(end 310.7944 -233.638344)
		(width 0.18288)
		(layer "In6.Cu")
		(net "M_C_CPU0_SB_DQS_DP<5>")
	)
	(segment
		(start 287.052004 -228.66858)
		(end 285.89097 -227.507546)
		(width 0.18288)
		(layer "In6.Cu")
		(net "M_C_CPU0_SB_DQS_DP<5>")
	)
	(segment
		(start 342.006936 -241.80546)
		(end 341.996522 -241.799364)
		(width 0.088646)
		(layer "In6.Cu")
		(net "M_C_CPU0_SB_DQS_DP<5>")
	)
	(segment
		(start 303.071022 -232.024428)
		(end 299.565314 -232.024428)
		(width 0.18288)
		(layer "In6.Cu")
		(net "M_C_CPU0_SB_DQS_DP<5>")
	)
	(segment
		(start 338.247482 -241.80546)
		(end 338.23275 -241.796824)
		(width 0.088646)
		(layer "In6.Cu")
		(net "M_C_CPU0_SB_DQS_DP<5>")
	)
	(segment
		(start 294.681402 -230.891842)
		(end 294.426894 -231.14635)
		(width 0.18288)
		(layer "In6.Cu")
		(net "M_C_CPU0_SB_DQS_DP<5>")
	)
	(segment
		(start 295.442894 -231.152192)
		(end 295.182544 -230.891842)
		(width 0.18288)
		(layer "In6.Cu")
		(net "M_C_CPU0_SB_DQS_DP<5>")
	)
	(segment
		(start 293.127938 -230.380286)
		(end 292.564058 -230.380286)
		(width 0.18288)
		(layer "In6.Cu")
		(net "M_C_CPU0_SB_DQS_DP<5>")
	)
	(segment
		(start 312.538618 -234.782106)
		(end 311.938162 -234.782106)
		(width 0.18288)
		(layer "In6.Cu")
		(net "M_C_CPU0_SB_DQS_DP<5>")
	)
	(segment
		(start 292.564058 -230.380286)
		(end 291.883338 -229.699566)
		(width 0.18288)
		(layer "In6.Cu")
		(net "M_C_CPU0_SB_DQS_DP<5>")
	)
	(segment
		(start 334.488536 -241.80546)
		(end 334.473804 -241.796824)
		(width 0.088646)
		(layer "In6.Cu")
		(net "M_C_CPU0_SB_DQS_DP<5>")
	)
	(segment
		(start 345.170506 -242.294918)
		(end 345.104974 -242.229386)
		(width 0.088646)
		(layer "In6.Cu")
		(net "M_C_CPU0_SB_DQS_DP<5>")
	)
	(segment
		(start 298.526962 -231.996234)
		(end 298.003722 -231.996234)
		(width 0.18288)
		(layer "In6.Cu")
		(net "M_C_CPU0_SB_DQS_DP<5>")
	)
	(segment
		(start 341.066882 -241.80546)
		(end 341.05215 -241.796824)
		(width 0.088646)
		(layer "In6.Cu")
		(net "M_C_CPU0_SB_DQS_DP<5>")
	)
	(segment
		(start 303.939194 -232.8926)
		(end 303.071022 -232.024428)
		(width 0.18288)
		(layer "In6.Cu")
		(net "M_C_CPU0_SB_DQS_DP<5>")
	)
	(segment
		(start 336.376518 -241.810286)
		(end 336.353404 -241.796824)
		(width 0.088646)
		(layer "In6.Cu")
		(net "M_C_CPU0_SB_DQS_DP<5>")
	)
	(segment
		(start 342.946482 -241.80546)
		(end 342.936068 -241.799364)
		(width 0.088646)
		(layer "In6.Cu")
		(net "M_C_CPU0_SB_DQS_DP<5>")
	)
	(segment
		(start 296.355262 -231.41051)
		(end 296.096944 -231.152192)
		(width 0.18288)
		(layer "In6.Cu")
		(net "M_C_CPU0_SB_DQS_DP<5>")
	)
	(segment
		(start 344.826082 -241.80546)
		(end 344.81135 -241.796824)
		(width 0.088646)
		(layer "In6.Cu")
		(net "M_C_CPU0_SB_DQS_DP<5>")
	)
	(arc
		(start 343.87155 -241.796824)
		(mid 343.595075 -241.729504)
		(end 343.320878 -241.80546)
		(width 0.088646)
		(layer "In6.Cu")
		(net "M_C_CPU0_SB_DQS_DP<5>")
	)
	(arc
		(start 336.742278 -241.80546)
		(mid 336.560027 -241.855571)
		(end 336.376518 -241.810286)
		(width 0.088646)
		(layer "In6.Cu")
		(net "M_C_CPU0_SB_DQS_DP<5>")
	)
	(arc
		(start 338.621878 -241.80546)
		(mid 338.43468 -241.855603)
		(end 338.247482 -241.80546)
		(width 0.088646)
		(layer "In6.Cu")
		(net "M_C_CPU0_SB_DQS_DP<5>")
	)
	(arc
		(start 342.381332 -241.80546)
		(mid 342.194134 -241.855603)
		(end 342.006936 -241.80546)
		(width 0.088646)
		(layer "In6.Cu")
		(net "M_C_CPU0_SB_DQS_DP<5>")
	)
	(arc
		(start 333.524606 -241.791998)
		(mid 333.321914 -241.732005)
		(end 333.111348 -241.750596)
		(width 0.088646)
		(layer "In6.Cu")
		(net "M_C_CPU0_SB_DQS_DP<5>")
	)
	(arc
		(start 340.501478 -241.80546)
		(mid 340.31428 -241.855603)
		(end 340.127082 -241.80546)
		(width 0.088646)
		(layer "In6.Cu")
		(net "M_C_CPU0_SB_DQS_DP<5>")
	)
	(arc
		(start 341.996522 -241.799364)
		(mid 341.71809 -241.729518)
		(end 341.441278 -241.80546)
		(width 0.088646)
		(layer "In6.Cu")
		(net "M_C_CPU0_SB_DQS_DP<5>")
	)
	(arc
		(start 345.104974 -242.229386)
		(mid 345.01773 -241.987298)
		(end 344.832178 -241.809016)
		(width 0.088646)
		(layer "In6.Cu")
		(net "M_C_CPU0_SB_DQS_DP<5>")
	)
	(arc
		(start 344.81135 -241.796824)
		(mid 344.534875 -241.729504)
		(end 344.260678 -241.80546)
		(width 0.088646)
		(layer "In6.Cu")
		(net "M_C_CPU0_SB_DQS_DP<5>")
	)
	(arc
		(start 336.353404 -241.796824)
		(mid 336.076929 -241.729504)
		(end 335.802732 -241.80546)
		(width 0.088646)
		(layer "In6.Cu")
		(net "M_C_CPU0_SB_DQS_DP<5>")
	)
	(arc
		(start 344.260678 -241.80546)
		(mid 344.07348 -241.855603)
		(end 343.886282 -241.80546)
		(width 0.088646)
		(layer "In6.Cu")
		(net "M_C_CPU0_SB_DQS_DP<5>")
	)
	(arc
		(start 333.922624 -241.80546)
		(mid 333.743614 -241.855757)
		(end 333.562452 -241.813842)
		(width 0.088646)
		(layer "In6.Cu")
		(net "M_C_CPU0_SB_DQS_DP<5>")
	)
	(arc
		(start 339.561678 -241.80546)
		(mid 339.37448 -241.855603)
		(end 339.187282 -241.80546)
		(width 0.088646)
		(layer "In6.Cu")
		(net "M_C_CPU0_SB_DQS_DP<5>")
	)
	(arc
		(start 337.682078 -241.80546)
		(mid 337.49488 -241.855603)
		(end 337.307682 -241.80546)
		(width 0.088646)
		(layer "In6.Cu")
		(net "M_C_CPU0_SB_DQS_DP<5>")
	)
	(arc
		(start 334.473804 -241.796824)
		(mid 334.197075 -241.729384)
		(end 333.922624 -241.80546)
		(width 0.088646)
		(layer "In6.Cu")
		(net "M_C_CPU0_SB_DQS_DP<5>")
	)
	(arc
		(start 332.43647 -241.485928)
		(mid 332.37566 -241.411987)
		(end 332.330298 -241.327686)
		(width 0.088646)
		(layer "In6.Cu")
		(net "M_C_CPU0_SB_DQS_DP<5>")
	)
	(arc
		(start 332.330298 -241.327686)
		(mid 332.284891 -241.243649)
		(end 332.224126 -241.169952)
		(width 0.088646)
		(layer "In6.Cu")
		(net "M_C_CPU0_SB_DQS_DP<5>")
	)
	(arc
		(start 341.441278 -241.80546)
		(mid 341.25408 -241.855603)
		(end 341.066882 -241.80546)
		(width 0.088646)
		(layer "In6.Cu")
		(net "M_C_CPU0_SB_DQS_DP<5>")
	)
	(arc
		(start 338.23275 -241.796824)
		(mid 337.956275 -241.729504)
		(end 337.682078 -241.80546)
		(width 0.088646)
		(layer "In6.Cu")
		(net "M_C_CPU0_SB_DQS_DP<5>")
	)
	(arc
		(start 341.05215 -241.796824)
		(mid 340.775675 -241.729504)
		(end 340.501478 -241.80546)
		(width 0.088646)
		(layer "In6.Cu")
		(net "M_C_CPU0_SB_DQS_DP<5>")
	)
	(arc
		(start 333.111348 -241.750596)
		(mid 332.81449 -241.753862)
		(end 332.556866 -241.606324)
		(width 0.088646)
		(layer "In6.Cu")
		(net "M_C_CPU0_SB_DQS_DP<5>")
	)
	(arc
		(start 343.320878 -241.80546)
		(mid 343.13368 -241.855603)
		(end 342.946482 -241.80546)
		(width 0.088646)
		(layer "In6.Cu")
		(net "M_C_CPU0_SB_DQS_DP<5>")
	)
	(arc
		(start 335.428336 -241.80546)
		(mid 335.154137 -241.729625)
		(end 334.877664 -241.796824)
		(width 0.088646)
		(layer "In6.Cu")
		(net "M_C_CPU0_SB_DQS_DP<5>")
	)
	(arc
		(start 342.936068 -241.799364)
		(mid 342.65789 -241.729641)
		(end 342.381332 -241.80546)
		(width 0.088646)
		(layer "In6.Cu")
		(net "M_C_CPU0_SB_DQS_DP<5>")
	)
	(arc
		(start 337.29295 -241.796824)
		(mid 337.016475 -241.729504)
		(end 336.742278 -241.80546)
		(width 0.088646)
		(layer "In6.Cu")
		(net "M_C_CPU0_SB_DQS_DP<5>")
	)
	(arc
		(start 340.11235 -241.796824)
		(mid 339.835875 -241.729504)
		(end 339.561678 -241.80546)
		(width 0.088646)
		(layer "In6.Cu")
		(net "M_C_CPU0_SB_DQS_DP<5>")
	)
	(arc
		(start 335.802732 -241.80546)
		(mid 335.615534 -241.855603)
		(end 335.428336 -241.80546)
		(width 0.088646)
		(layer "In6.Cu")
		(net "M_C_CPU0_SB_DQS_DP<5>")
	)
	(arc
		(start 334.862932 -241.80546)
		(mid 334.675734 -241.855603)
		(end 334.488536 -241.80546)
		(width 0.088646)
		(layer "In6.Cu")
		(net "M_C_CPU0_SB_DQS_DP<5>")
	)
	(arc
		(start 339.17255 -241.796824)
		(mid 338.896075 -241.729504)
		(end 338.621878 -241.80546)
		(width 0.088646)
		(layer "In6.Cu")
		(net "M_C_CPU0_SB_DQS_DP<5>")
	)
	(segment
		(start 342.194134 -239.85347)
		(end 342.19388 -239.853216)
		(width 0.20066)
		(layer "F.Cu")
		(net "M_C_CPU0_SB_DQS_DP<4>")
	)
	(segment
		(start 282.811982 -236.416596)
		(end 282.32227 -236.416596)
		(width 0.20066)
		(layer "F.Cu")
		(net "M_C_CPU0_SB_DQS_DP<4>")
	)
	(segment
		(start 280.05405 -235.991654)
		(end 279.965404 -235.991654)
		(width 0.20066)
		(layer "F.Cu")
		(net "M_C_CPU0_SB_DQS_DP<4>")
	)
	(segment
		(start 277.834598 -235.991654)
		(end 277.444708 -235.991654)
		(width 0.101854)
		(layer "F.Cu")
		(net "M_C_CPU0_SB_DQS_DP<4>")
	)
	(segment
		(start 280.820368 -236.25302)
		(end 280.315416 -236.25302)
		(width 0.20066)
		(layer "F.Cu")
		(net "M_C_CPU0_SB_DQS_DP<4>")
	)
	(segment
		(start 279.965404 -235.991654)
		(end 279.912572 -235.991654)
		(width 0.101854)
		(layer "F.Cu")
		(net "M_C_CPU0_SB_DQS_DP<4>")
	)
	(segment
		(start 279.912572 -235.991654)
		(end 277.834598 -235.991654)
		(width 0.1016)
		(layer "F.Cu")
		(net "M_C_CPU0_SB_DQS_DP<4>")
	)
	(segment
		(start 275.742654 -236.416596)
		(end 275.268182 -236.416596)
		(width 0.20066)
		(layer "F.Cu")
		(net "M_C_CPU0_SB_DQS_DP<4>")
	)
	(segment
		(start 282.060904 -236.677962)
		(end 281.456384 -236.677962)
		(width 0.20066)
		(layer "F.Cu")
		(net "M_C_CPU0_SB_DQS_DP<4>")
	)
	(segment
		(start 282.32227 -236.416596)
		(end 282.060904 -236.677962)
		(width 0.20066)
		(layer "F.Cu")
		(net "M_C_CPU0_SB_DQS_DP<4>")
	)
	(segment
		(start 277.120858 -236.25556)
		(end 276.760686 -236.25556)
		(width 0.20066)
		(layer "F.Cu")
		(net "M_C_CPU0_SB_DQS_DP<4>")
	)
	(segment
		(start 283.916882 -236.416596)
		(end 282.811982 -236.416596)
		(width 0.20066)
		(layer "F.Cu")
		(net "M_C_CPU0_SB_DQS_DP<4>")
	)
	(segment
		(start 281.456384 -236.677962)
		(end 280.820368 -236.25302)
		(width 0.20066)
		(layer "F.Cu")
		(net "M_C_CPU0_SB_DQS_DP<4>")
	)
	(segment
		(start 342.194134 -240.389156)
		(end 342.194134 -239.85347)
		(width 0.20066)
		(layer "F.Cu")
		(net "M_C_CPU0_SB_DQS_DP<4>")
	)
	(segment
		(start 276.760686 -236.25556)
		(end 276.338284 -236.677962)
		(width 0.20066)
		(layer "F.Cu")
		(net "M_C_CPU0_SB_DQS_DP<4>")
	)
	(segment
		(start 277.444708 -235.991654)
		(end 277.384764 -235.991654)
		(width 0.20066)
		(layer "F.Cu")
		(net "M_C_CPU0_SB_DQS_DP<4>")
	)
	(segment
		(start 277.384764 -235.991654)
		(end 277.120858 -236.25556)
		(width 0.20066)
		(layer "F.Cu")
		(net "M_C_CPU0_SB_DQS_DP<4>")
	)
	(segment
		(start 280.315416 -236.25302)
		(end 280.05405 -235.991654)
		(width 0.20066)
		(layer "F.Cu")
		(net "M_C_CPU0_SB_DQS_DP<4>")
	)
	(segment
		(start 276.338284 -236.677962)
		(end 276.00402 -236.677962)
		(width 0.20066)
		(layer "F.Cu")
		(net "M_C_CPU0_SB_DQS_DP<4>")
	)
	(segment
		(start 276.00402 -236.677962)
		(end 275.742654 -236.416596)
		(width 0.20066)
		(layer "F.Cu")
		(net "M_C_CPU0_SB_DQS_DP<4>")
	)
	(segment
		(start 295.090596 -235.991654)
		(end 294.710358 -235.991654)
		(width 0.18288)
		(layer "In4.Cu")
		(net "M_C_CPU0_SB_DQS_DP<4>")
	)
	(segment
		(start 308.733698 -235.684568)
		(end 307.366924 -235.684568)
		(width 0.18288)
		(layer "In4.Cu")
		(net "M_C_CPU0_SB_DQS_DP<4>")
	)
	(segment
		(start 332.79588 -240.228628)
		(end 332.075028 -240.228628)
		(width 0.088646)
		(layer "In4.Cu")
		(net "M_C_CPU0_SB_DQS_DP<4>")
	)
	(segment
		(start 288.436304 -236.087412)
		(end 287.625282 -236.898434)
		(width 0.18288)
		(layer "In4.Cu")
		(net "M_C_CPU0_SB_DQS_DP<4>")
	)
	(segment
		(start 299.186092 -235.14177)
		(end 298.811442 -235.14177)
		(width 0.18288)
		(layer "In4.Cu")
		(net "M_C_CPU0_SB_DQS_DP<4>")
	)
	(segment
		(start 303.550828 -236.230414)
		(end 302.923956 -236.857286)
		(width 0.18288)
		(layer "In4.Cu")
		(net "M_C_CPU0_SB_DQS_DP<4>")
	)
	(segment
		(start 298.54652 -235.406692)
		(end 298.079922 -235.406692)
		(width 0.18288)
		(layer "In4.Cu")
		(net "M_C_CPU0_SB_DQS_DP<4>")
	)
	(segment
		(start 284.91688 -236.898434)
		(end 284.703774 -236.685328)
		(width 0.18288)
		(layer "In4.Cu")
		(net "M_C_CPU0_SB_DQS_DP<4>")
	)
	(segment
		(start 299.460412 -235.41609)
		(end 299.186092 -235.14177)
		(width 0.18288)
		(layer "In4.Cu")
		(net "M_C_CPU0_SB_DQS_DP<4>")
	)
	(segment
		(start 342.19388 -239.853216)
		(end 341.399368 -239.41659)
		(width 0.088646)
		(layer "In4.Cu")
		(net "M_C_CPU0_SB_DQS_DP<4>")
	)
	(segment
		(start 332.075028 -240.228628)
		(end 331.775816 -240.52784)
		(width 0.088646)
		(layer "In4.Cu")
		(net "M_C_CPU0_SB_DQS_DP<4>")
	)
	(segment
		(start 315.793882 -237.137702)
		(end 310.186832 -237.137702)
		(width 0.18288)
		(layer "In4.Cu")
		(net "M_C_CPU0_SB_DQS_DP<4>")
	)
	(segment
		(start 284.703774 -236.685328)
		(end 284.185614 -236.685328)
		(width 0.18288)
		(layer "In4.Cu")
		(net "M_C_CPU0_SB_DQS_DP<4>")
	)
	(segment
		(start 293.741094 -236.264704)
		(end 293.124128 -235.647738)
		(width 0.18288)
		(layer "In4.Cu")
		(net "M_C_CPU0_SB_DQS_DP<4>")
	)
	(segment
		(start 292.22446 -235.647738)
		(end 291.784786 -236.087412)
		(width 0.18288)
		(layer "In4.Cu")
		(net "M_C_CPU0_SB_DQS_DP<4>")
	)
	(segment
		(start 293.124128 -235.647738)
		(end 292.22446 -235.647738)
		(width 0.18288)
		(layer "In4.Cu")
		(net "M_C_CPU0_SB_DQS_DP<4>")
	)
	(segment
		(start 307.366924 -235.684568)
		(end 306.821078 -236.230414)
		(width 0.18288)
		(layer "In4.Cu")
		(net "M_C_CPU0_SB_DQS_DP<4>")
	)
	(segment
		(start 331.775816 -240.52784)
		(end 331.099414 -240.52784)
		(width 0.088646)
		(layer "In4.Cu")
		(net "M_C_CPU0_SB_DQS_DP<4>")
	)
	(segment
		(start 302.1838 -236.857286)
		(end 300.742604 -235.41609)
		(width 0.18288)
		(layer "In4.Cu")
		(net "M_C_CPU0_SB_DQS_DP<4>")
	)
	(segment
		(start 336.287364 -239.355122)
		(end 336.272632 -239.363758)
		(width 0.088646)
		(layer "In4.Cu")
		(net "M_C_CPU0_SB_DQS_DP<4>")
	)
	(segment
		(start 298.079922 -235.406692)
		(end 297.230038 -236.256576)
		(width 0.18288)
		(layer "In4.Cu")
		(net "M_C_CPU0_SB_DQS_DP<4>")
	)
	(segment
		(start 331.099414 -240.52784)
		(end 331.039724 -240.46815)
		(width 0.088646)
		(layer "In4.Cu")
		(net "M_C_CPU0_SB_DQS_DP<4>")
	)
	(segment
		(start 334.39227 -239.364266)
		(end 334.386936 -239.367314)
		(width 0.088646)
		(layer "In4.Cu")
		(net "M_C_CPU0_SB_DQS_DP<4>")
	)
	(segment
		(start 340.046564 -239.355122)
		(end 340.031832 -239.363758)
		(width 0.088646)
		(layer "In4.Cu")
		(net "M_C_CPU0_SB_DQS_DP<4>")
	)
	(segment
		(start 302.923956 -236.857286)
		(end 302.1838 -236.857286)
		(width 0.18288)
		(layer "In4.Cu")
		(net "M_C_CPU0_SB_DQS_DP<4>")
	)
	(segment
		(start 319.12433 -240.46815)
		(end 315.793882 -237.137702)
		(width 0.18288)
		(layer "In4.Cu")
		(net "M_C_CPU0_SB_DQS_DP<4>")
	)
	(segment
		(start 294.437308 -236.264704)
		(end 293.741094 -236.264704)
		(width 0.18288)
		(layer "In4.Cu")
		(net "M_C_CPU0_SB_DQS_DP<4>")
	)
	(segment
		(start 306.821078 -236.230414)
		(end 303.550828 -236.230414)
		(width 0.18288)
		(layer "In4.Cu")
		(net "M_C_CPU0_SB_DQS_DP<4>")
	)
	(segment
		(start 284.185614 -236.685328)
		(end 283.916882 -236.416596)
		(width 0.18288)
		(layer "In4.Cu")
		(net "M_C_CPU0_SB_DQS_DP<4>")
	)
	(segment
		(start 298.811442 -235.14177)
		(end 298.54652 -235.406692)
		(width 0.18288)
		(layer "In4.Cu")
		(net "M_C_CPU0_SB_DQS_DP<4>")
	)
	(segment
		(start 333.548482 -240.177574)
		(end 333.53375 -240.168938)
		(width 0.088646)
		(layer "In4.Cu")
		(net "M_C_CPU0_SB_DQS_DP<4>")
	)
	(segment
		(start 300.742604 -235.41609)
		(end 299.460412 -235.41609)
		(width 0.18288)
		(layer "In4.Cu")
		(net "M_C_CPU0_SB_DQS_DP<4>")
	)
	(segment
		(start 331.039724 -240.46815)
		(end 331.004164 -240.46815)
		(width 0.088646)
		(layer "In4.Cu")
		(net "M_C_CPU0_SB_DQS_DP<4>")
	)
	(segment
		(start 291.784786 -236.087412)
		(end 288.436304 -236.087412)
		(width 0.18288)
		(layer "In4.Cu")
		(net "M_C_CPU0_SB_DQS_DP<4>")
	)
	(segment
		(start 310.186832 -237.137702)
		(end 308.733698 -235.684568)
		(width 0.18288)
		(layer "In4.Cu")
		(net "M_C_CPU0_SB_DQS_DP<4>")
	)
	(segment
		(start 295.355518 -236.256576)
		(end 295.090596 -235.991654)
		(width 0.18288)
		(layer "In4.Cu")
		(net "M_C_CPU0_SB_DQS_DP<4>")
	)
	(segment
		(start 294.710358 -235.991654)
		(end 294.437308 -236.264704)
		(width 0.18288)
		(layer "In4.Cu")
		(net "M_C_CPU0_SB_DQS_DP<4>")
	)
	(segment
		(start 335.347564 -239.355122)
		(end 335.332832 -239.363758)
		(width 0.088646)
		(layer "In4.Cu")
		(net "M_C_CPU0_SB_DQS_DP<4>")
	)
	(segment
		(start 339.106764 -239.355122)
		(end 339.092032 -239.363758)
		(width 0.088646)
		(layer "In4.Cu")
		(net "M_C_CPU0_SB_DQS_DP<4>")
	)
	(segment
		(start 334.407764 -239.355122)
		(end 334.39227 -239.364266)
		(width 0.088646)
		(layer "In4.Cu")
		(net "M_C_CPU0_SB_DQS_DP<4>")
	)
	(segment
		(start 297.230038 -236.256576)
		(end 295.355518 -236.256576)
		(width 0.18288)
		(layer "In4.Cu")
		(net "M_C_CPU0_SB_DQS_DP<4>")
	)
	(segment
		(start 287.625282 -236.898434)
		(end 284.91688 -236.898434)
		(width 0.18288)
		(layer "In4.Cu")
		(net "M_C_CPU0_SB_DQS_DP<4>")
	)
	(segment
		(start 331.004164 -240.46815)
		(end 319.12433 -240.46815)
		(width 0.18288)
		(layer "In4.Cu")
		(net "M_C_CPU0_SB_DQS_DP<4>")
	)
	(segment
		(start 337.227164 -239.355122)
		(end 337.212432 -239.363758)
		(width 0.088646)
		(layer "In4.Cu")
		(net "M_C_CPU0_SB_DQS_DP<4>")
	)
	(arc
		(start 340.859364 -239.40643)
		(mid 340.724405 -239.409067)
		(end 340.597236 -239.363758)
		(width 0.088646)
		(layer "In4.Cu")
		(net "M_C_CPU0_SB_DQS_DP<4>")
	)
	(arc
		(start 340.031832 -239.363758)
		(mid 339.844634 -239.413901)
		(end 339.657436 -239.363758)
		(width 0.088646)
		(layer "In4.Cu")
		(net "M_C_CPU0_SB_DQS_DP<4>")
	)
	(arc
		(start 334.958436 -239.363758)
		(mid 334.684237 -239.287923)
		(end 334.407764 -239.355122)
		(width 0.088646)
		(layer "In4.Cu")
		(net "M_C_CPU0_SB_DQS_DP<4>")
	)
	(arc
		(start 335.332832 -239.363758)
		(mid 335.145634 -239.413901)
		(end 334.958436 -239.363758)
		(width 0.088646)
		(layer "In4.Cu")
		(net "M_C_CPU0_SB_DQS_DP<4>")
	)
	(arc
		(start 333.53375 -240.168938)
		(mid 333.257309 -240.101772)
		(end 332.983078 -240.177574)
		(width 0.088646)
		(layer "In4.Cu")
		(net "M_C_CPU0_SB_DQS_DP<4>")
	)
	(arc
		(start 339.657436 -239.363758)
		(mid 339.383237 -239.287923)
		(end 339.106764 -239.355122)
		(width 0.088646)
		(layer "In4.Cu")
		(net "M_C_CPU0_SB_DQS_DP<4>")
	)
	(arc
		(start 337.777836 -239.363758)
		(mid 337.503637 -239.287923)
		(end 337.227164 -239.355122)
		(width 0.088646)
		(layer "In4.Cu")
		(net "M_C_CPU0_SB_DQS_DP<4>")
	)
	(arc
		(start 334.110076 -239.867948)
		(mid 333.916582 -240.181095)
		(end 333.548482 -240.177574)
		(width 0.088646)
		(layer "In4.Cu")
		(net "M_C_CPU0_SB_DQS_DP<4>")
	)
	(arc
		(start 336.838036 -239.363758)
		(mid 336.563837 -239.287923)
		(end 336.287364 -239.355122)
		(width 0.088646)
		(layer "In4.Cu")
		(net "M_C_CPU0_SB_DQS_DP<4>")
	)
	(arc
		(start 341.399368 -239.41659)
		(mid 341.358385 -239.398758)
		(end 341.314786 -239.388904)
		(width 0.088646)
		(layer "In4.Cu")
		(net "M_C_CPU0_SB_DQS_DP<4>")
	)
	(arc
		(start 337.212432 -239.363758)
		(mid 337.025234 -239.413901)
		(end 336.838036 -239.363758)
		(width 0.088646)
		(layer "In4.Cu")
		(net "M_C_CPU0_SB_DQS_DP<4>")
	)
	(arc
		(start 334.11033 -239.853216)
		(mid 334.110278 -239.860583)
		(end 334.110076 -239.867948)
		(width 0.088646)
		(layer "In4.Cu")
		(net "M_C_CPU0_SB_DQS_DP<4>")
	)
	(arc
		(start 341.314786 -239.388904)
		(mid 341.086362 -239.379117)
		(end 340.859364 -239.40643)
		(width 0.088646)
		(layer "In4.Cu")
		(net "M_C_CPU0_SB_DQS_DP<4>")
	)
	(arc
		(start 338.717636 -239.363758)
		(mid 338.434934 -239.287982)
		(end 338.152232 -239.363758)
		(width 0.088646)
		(layer "In4.Cu")
		(net "M_C_CPU0_SB_DQS_DP<4>")
	)
	(arc
		(start 335.898236 -239.363758)
		(mid 335.624037 -239.287923)
		(end 335.347564 -239.355122)
		(width 0.088646)
		(layer "In4.Cu")
		(net "M_C_CPU0_SB_DQS_DP<4>")
	)
	(arc
		(start 340.597236 -239.363758)
		(mid 340.323037 -239.287923)
		(end 340.046564 -239.355122)
		(width 0.088646)
		(layer "In4.Cu")
		(net "M_C_CPU0_SB_DQS_DP<4>")
	)
	(arc
		(start 338.152232 -239.363758)
		(mid 337.965034 -239.413901)
		(end 337.777836 -239.363758)
		(width 0.088646)
		(layer "In4.Cu")
		(net "M_C_CPU0_SB_DQS_DP<4>")
	)
	(arc
		(start 339.092032 -239.363758)
		(mid 338.904834 -239.413901)
		(end 338.717636 -239.363758)
		(width 0.088646)
		(layer "In4.Cu")
		(net "M_C_CPU0_SB_DQS_DP<4>")
	)
	(arc
		(start 334.386936 -239.367314)
		(mid 334.184349 -239.573665)
		(end 334.11033 -239.853216)
		(width 0.088646)
		(layer "In4.Cu")
		(net "M_C_CPU0_SB_DQS_DP<4>")
	)
	(arc
		(start 332.983078 -240.177574)
		(mid 332.892842 -240.215444)
		(end 332.79588 -240.228628)
		(width 0.088646)
		(layer "In4.Cu")
		(net "M_C_CPU0_SB_DQS_DP<4>")
	)
	(arc
		(start 336.272632 -239.363758)
		(mid 336.085434 -239.413901)
		(end 335.898236 -239.363758)
		(width 0.088646)
		(layer "In4.Cu")
		(net "M_C_CPU0_SB_DQS_DP<4>")
	)
	(segment
		(start 273.925792 -201.151236)
		(end 273.655282 -200.880726)
		(width 0.20066)
		(layer "F.Cu")
		(net "M_C_CPU0_SB_DQS_DP<3>")
	)
	(segment
		(start 274.143978 -201.151236)
		(end 273.925792 -201.151236)
		(width 0.20066)
		(layer "F.Cu")
		(net "M_C_CPU0_SB_DQS_DP<3>")
	)
	(segment
		(start 343.603834 -228.180646)
		(end 343.603834 -227.64496)
		(width 0.20066)
		(layer "F.Cu")
		(net "M_C_CPU0_SB_DQS_DP<3>")
	)
	(segment
		(start 274.390358 -201.141838)
		(end 274.153376 -201.141838)
		(width 0.101854)
		(layer "F.Cu")
		(net "M_C_CPU0_SB_DQS_DP<3>")
	)
	(segment
		(start 343.60358 -228.1809)
		(end 343.603834 -228.180646)
		(width 0.20066)
		(layer "F.Cu")
		(net "M_C_CPU0_SB_DQS_DP<3>")
	)
	(segment
		(start 277.63343 -200.45553)
		(end 277.208234 -200.880726)
		(width 0.20066)
		(layer "F.Cu")
		(net "M_C_CPU0_SB_DQS_DP<3>")
	)
	(segment
		(start 276.882352 -200.880726)
		(end 276.62124 -201.141838)
		(width 0.20066)
		(layer "F.Cu")
		(net "M_C_CPU0_SB_DQS_DP<3>")
	)
	(segment
		(start 276.145752 -201.141838)
		(end 274.390358 -201.141838)
		(width 0.1016)
		(layer "F.Cu")
		(net "M_C_CPU0_SB_DQS_DP<3>")
	)
	(segment
		(start 272.39214 -200.45553)
		(end 271.967198 -200.45553)
		(width 0.20066)
		(layer "F.Cu")
		(net "M_C_CPU0_SB_DQS_DP<3>")
	)
	(segment
		(start 278.711914 -200.716642)
		(end 278.163274 -200.716642)
		(width 0.20066)
		(layer "F.Cu")
		(net "M_C_CPU0_SB_DQS_DP<3>")
	)
	(segment
		(start 276.62124 -201.141838)
		(end 276.469094 -201.141838)
		(width 0.20066)
		(layer "F.Cu")
		(net "M_C_CPU0_SB_DQS_DP<3>")
	)
	(segment
		(start 279.816814 -200.716642)
		(end 278.711914 -200.716642)
		(width 0.20066)
		(layer "F.Cu")
		(net "M_C_CPU0_SB_DQS_DP<3>")
	)
	(segment
		(start 274.153376 -201.141838)
		(end 274.143978 -201.151236)
		(width 0.101854)
		(layer "F.Cu")
		(net "M_C_CPU0_SB_DQS_DP<3>")
	)
	(segment
		(start 271.706086 -200.716642)
		(end 271.168114 -200.716642)
		(width 0.20066)
		(layer "F.Cu")
		(net "M_C_CPU0_SB_DQS_DP<3>")
	)
	(segment
		(start 276.469094 -201.141838)
		(end 276.145752 -201.141838)
		(width 0.101854)
		(layer "F.Cu")
		(net "M_C_CPU0_SB_DQS_DP<3>")
	)
	(segment
		(start 271.967198 -200.45553)
		(end 271.706086 -200.716642)
		(width 0.20066)
		(layer "F.Cu")
		(net "M_C_CPU0_SB_DQS_DP<3>")
	)
	(segment
		(start 278.163274 -200.716642)
		(end 277.902162 -200.45553)
		(width 0.20066)
		(layer "F.Cu")
		(net "M_C_CPU0_SB_DQS_DP<3>")
	)
	(segment
		(start 277.208234 -200.880726)
		(end 276.882352 -200.880726)
		(width 0.20066)
		(layer "F.Cu")
		(net "M_C_CPU0_SB_DQS_DP<3>")
	)
	(segment
		(start 277.902162 -200.45553)
		(end 277.63343 -200.45553)
		(width 0.20066)
		(layer "F.Cu")
		(net "M_C_CPU0_SB_DQS_DP<3>")
	)
	(segment
		(start 273.655282 -200.880726)
		(end 273.028156 -200.880726)
		(width 0.20066)
		(layer "F.Cu")
		(net "M_C_CPU0_SB_DQS_DP<3>")
	)
	(segment
		(start 273.028156 -200.880726)
		(end 272.39214 -200.45553)
		(width 0.20066)
		(layer "F.Cu")
		(net "M_C_CPU0_SB_DQS_DP<3>")
	)
	(segment
		(start 296.312082 -199.166988)
		(end 295.356788 -199.166988)
		(width 0.18288)
		(layer "In6.Cu")
		(net "M_C_CPU0_SB_DQS_DP<3>")
	)
	(segment
		(start 293.6748 -199.168004)
		(end 293.156132 -198.649336)
		(width 0.18288)
		(layer "In6.Cu")
		(net "M_C_CPU0_SB_DQS_DP<3>")
	)
	(segment
		(start 283.720286 -201.142346)
		(end 283.448506 -200.870566)
		(width 0.18288)
		(layer "In6.Cu")
		(net "M_C_CPU0_SB_DQS_DP<3>")
	)
	(segment
		(start 333.074518 -225.69551)
		(end 333.060548 -225.703384)
		(width 0.088646)
		(layer "In6.Cu")
		(net "M_C_CPU0_SB_DQS_DP<3>")
	)
	(segment
		(start 287.179766 -199.4535)
		(end 286.890206 -199.16394)
		(width 0.18288)
		(layer "In6.Cu")
		(net "M_C_CPU0_SB_DQS_DP<3>")
	)
	(segment
		(start 342.633808 -228.01834)
		(end 342.576658 -228.011482)
		(width 0.088646)
		(layer "In6.Cu")
		(net "M_C_CPU0_SB_DQS_DP<3>")
	)
	(segment
		(start 280.098754 -200.434702)
		(end 279.816814 -200.716642)
		(width 0.18288)
		(layer "In6.Cu")
		(net "M_C_CPU0_SB_DQS_DP<3>")
	)
	(segment
		(start 327.879456 -222.755206)
		(end 327.879456 -220.105732)
		(width 0.18288)
		(layer "In6.Cu")
		(net "M_C_CPU0_SB_DQS_DP<3>")
	)
	(segment
		(start 281.75839 -200.208896)
		(end 281.146504 -200.208896)
		(width 0.18288)
		(layer "In6.Cu")
		(net "M_C_CPU0_SB_DQS_DP<3>")
	)
	(segment
		(start 294.447722 -199.168004)
		(end 293.6748 -199.168004)
		(width 0.18288)
		(layer "In6.Cu")
		(net "M_C_CPU0_SB_DQS_DP<3>")
	)
	(segment
		(start 314.168282 -203.398374)
		(end 313.752738 -203.398374)
		(width 0.18288)
		(layer "In6.Cu")
		(net "M_C_CPU0_SB_DQS_DP<3>")
	)
	(segment
		(start 336.272632 -227.320602)
		(end 336.266536 -227.317046)
		(width 0.088646)
		(layer "In6.Cu")
		(net "M_C_CPU0_SB_DQS_DP<3>")
	)
	(segment
		(start 339.657182 -227.320602)
		(end 339.646768 -227.326698)
		(width 0.088646)
		(layer "In6.Cu")
		(net "M_C_CPU0_SB_DQS_DP<3>")
	)
	(segment
		(start 287.821878 -199.173846)
		(end 287.542224 -199.4535)
		(width 0.18288)
		(layer "In6.Cu")
		(net "M_C_CPU0_SB_DQS_DP<3>")
	)
	(segment
		(start 298.528994 -198.32574)
		(end 298.342812 -198.32574)
		(width 0.18288)
		(layer "In6.Cu")
		(net "M_C_CPU0_SB_DQS_DP<3>")
	)
	(segment
		(start 342.216232 -228.014022)
		(end 341.992712 -228.1428)
		(width 0.088646)
		(layer "In6.Cu")
		(net "M_C_CPU0_SB_DQS_DP<3>")
	)
	(segment
		(start 341.441532 -228.134418)
		(end 341.441278 -228.134672)
		(width 0.088646)
		(layer "In6.Cu")
		(net "M_C_CPU0_SB_DQS_DP<3>")
	)
	(segment
		(start 336.287364 -227.329238)
		(end 336.272632 -227.320602)
		(width 0.088646)
		(layer "In6.Cu")
		(net "M_C_CPU0_SB_DQS_DP<3>")
	)
	(segment
		(start 301.91964 -199.776334)
		(end 300.447456 -198.305166)
		(width 0.18288)
		(layer "In6.Cu")
		(net "M_C_CPU0_SB_DQS_DP<3>")
	)
	(segment
		(start 312.329068 -201.974704)
		(end 307.023516 -199.776334)
		(width 0.18288)
		(layer "In6.Cu")
		(net "M_C_CPU0_SB_DQS_DP<3>")
	)
	(segment
		(start 333.078582 -225.69297)
		(end 333.074518 -225.69551)
		(width 0.088646)
		(layer "In6.Cu")
		(net "M_C_CPU0_SB_DQS_DP<3>")
	)
	(segment
		(start 341.066882 -228.134672)
		(end 341.05215 -228.143308)
		(width 0.088646)
		(layer "In6.Cu")
		(net "M_C_CPU0_SB_DQS_DP<3>")
	)
	(segment
		(start 300.447456 -198.305166)
		(end 299.470826 -198.305166)
		(width 0.18288)
		(layer "In6.Cu")
		(net "M_C_CPU0_SB_DQS_DP<3>")
	)
	(segment
		(start 338.166964 -227.329238)
		(end 338.152232 -227.320602)
		(width 0.088646)
		(layer "In6.Cu")
		(net "M_C_CPU0_SB_DQS_DP<3>")
	)
	(segment
		(start 298.79417 -198.590916)
		(end 298.528994 -198.32574)
		(width 0.18288)
		(layer "In6.Cu")
		(net "M_C_CPU0_SB_DQS_DP<3>")
	)
	(segment
		(start 335.98993 -226.831144)
		(end 335.98993 -226.822508)
		(width 0.088646)
		(layer "In6.Cu")
		(net "M_C_CPU0_SB_DQS_DP<3>")
	)
	(segment
		(start 288.089594 -199.173846)
		(end 287.821878 -199.173846)
		(width 0.18288)
		(layer "In6.Cu")
		(net "M_C_CPU0_SB_DQS_DP<3>")
	)
	(segment
		(start 292.950646 -198.564246)
		(end 292.639242 -198.564246)
		(width 0.18288)
		(layer "In6.Cu")
		(net "M_C_CPU0_SB_DQS_DP<3>")
	)
	(segment
		(start 295.356788 -199.166988)
		(end 295.082976 -199.4408)
		(width 0.18288)
		(layer "In6.Cu")
		(net "M_C_CPU0_SB_DQS_DP<3>")
	)
	(segment
		(start 299.470826 -198.305166)
		(end 299.185076 -198.590916)
		(width 0.18288)
		(layer "In6.Cu")
		(net "M_C_CPU0_SB_DQS_DP<3>")
	)
	(segment
		(start 330.443078 -223.419924)
		(end 330.41971 -223.419924)
		(width 0.088646)
		(layer "In6.Cu")
		(net "M_C_CPU0_SB_DQS_DP<3>")
	)
	(segment
		(start 286.890206 -199.16394)
		(end 286.643572 -199.16394)
		(width 0.18288)
		(layer "In6.Cu")
		(net "M_C_CPU0_SB_DQS_DP<3>")
	)
	(segment
		(start 281.146504 -200.208896)
		(end 280.60142 -200.434702)
		(width 0.18288)
		(layer "In6.Cu")
		(net "M_C_CPU0_SB_DQS_DP<3>")
	)
	(segment
		(start 343.263474 -227.734876)
		(end 342.838278 -227.976684)
		(width 0.088646)
		(layer "In6.Cu")
		(net "M_C_CPU0_SB_DQS_DP<3>")
	)
	(segment
		(start 290.47948 -199.459088)
		(end 288.778442 -199.459088)
		(width 0.18288)
		(layer "In6.Cu")
		(net "M_C_CPU0_SB_DQS_DP<3>")
	)
	(segment
		(start 286.643572 -199.16394)
		(end 285.847282 -199.49414)
		(width 0.18288)
		(layer "In6.Cu")
		(net "M_C_CPU0_SB_DQS_DP<3>")
	)
	(segment
		(start 331.0001 -224.207324)
		(end 331.0001 -223.559624)
		(width 0.088646)
		(layer "In6.Cu")
		(net "M_C_CPU0_SB_DQS_DP<3>")
	)
	(segment
		(start 331.0001 -223.559624)
		(end 330.800456 -223.35998)
		(width 0.088646)
		(layer "In6.Cu")
		(net "M_C_CPU0_SB_DQS_DP<3>")
	)
	(segment
		(start 332.39583 -225.603054)
		(end 331.0001 -224.207324)
		(width 0.088646)
		(layer "In6.Cu")
		(net "M_C_CPU0_SB_DQS_DP<3>")
	)
	(segment
		(start 282.227782 -200.403206)
		(end 281.75839 -200.208896)
		(width 0.18288)
		(layer "In6.Cu")
		(net "M_C_CPU0_SB_DQS_DP<3>")
	)
	(segment
		(start 330.41971 -223.419924)
		(end 328.544174 -223.419924)
		(width 0.18288)
		(layer "In6.Cu")
		(net "M_C_CPU0_SB_DQS_DP<3>")
	)
	(segment
		(start 317.19139 -206.421482)
		(end 314.168282 -203.398374)
		(width 0.18288)
		(layer "In6.Cu")
		(net "M_C_CPU0_SB_DQS_DP<3>")
	)
	(segment
		(start 294.720518 -199.4408)
		(end 294.447722 -199.168004)
		(width 0.18288)
		(layer "In6.Cu")
		(net "M_C_CPU0_SB_DQS_DP<3>")
	)
	(segment
		(start 328.544174 -223.419924)
		(end 327.879456 -222.755206)
		(width 0.18288)
		(layer "In6.Cu")
		(net "M_C_CPU0_SB_DQS_DP<3>")
	)
	(segment
		(start 284.199076 -201.142346)
		(end 283.720286 -201.142346)
		(width 0.18288)
		(layer "In6.Cu")
		(net "M_C_CPU0_SB_DQS_DP<3>")
	)
	(segment
		(start 335.341468 -225.69805)
		(end 335.332578 -225.69297)
		(width 0.088646)
		(layer "In6.Cu")
		(net "M_C_CPU0_SB_DQS_DP<3>")
	)
	(segment
		(start 282.695142 -200.870566)
		(end 282.227782 -200.403206)
		(width 0.18288)
		(layer "In6.Cu")
		(net "M_C_CPU0_SB_DQS_DP<3>")
	)
	(segment
		(start 330.503022 -223.35998)
		(end 330.443078 -223.419924)
		(width 0.088646)
		(layer "In6.Cu")
		(net "M_C_CPU0_SB_DQS_DP<3>")
	)
	(segment
		(start 293.156132 -198.649336)
		(end 292.950646 -198.564246)
		(width 0.18288)
		(layer "In6.Cu")
		(net "M_C_CPU0_SB_DQS_DP<3>")
	)
	(segment
		(start 330.800456 -223.35998)
		(end 330.503022 -223.35998)
		(width 0.088646)
		(layer "In6.Cu")
		(net "M_C_CPU0_SB_DQS_DP<3>")
	)
	(segment
		(start 288.778442 -199.459088)
		(end 288.089594 -199.173846)
		(width 0.18288)
		(layer "In6.Cu")
		(net "M_C_CPU0_SB_DQS_DP<3>")
	)
	(segment
		(start 335.802732 -226.506786)
		(end 335.79054 -226.499674)
		(width 0.088646)
		(layer "In6.Cu")
		(net "M_C_CPU0_SB_DQS_DP<3>")
	)
	(segment
		(start 313.752738 -203.398374)
		(end 312.329068 -201.974704)
		(width 0.18288)
		(layer "In6.Cu")
		(net "M_C_CPU0_SB_DQS_DP<3>")
	)
	(segment
		(start 342.576658 -228.011482)
		(end 342.571832 -228.014022)
		(width 0.088646)
		(layer "In6.Cu")
		(net "M_C_CPU0_SB_DQS_DP<3>")
	)
	(segment
		(start 337.227164 -227.329238)
		(end 337.212432 -227.320602)
		(width 0.088646)
		(layer "In6.Cu")
		(net "M_C_CPU0_SB_DQS_DP<3>")
	)
	(segment
		(start 285.847282 -199.49414)
		(end 284.199076 -201.142346)
		(width 0.18288)
		(layer "In6.Cu")
		(net "M_C_CPU0_SB_DQS_DP<3>")
	)
	(segment
		(start 299.185076 -198.590916)
		(end 298.79417 -198.590916)
		(width 0.18288)
		(layer "In6.Cu")
		(net "M_C_CPU0_SB_DQS_DP<3>")
	)
	(segment
		(start 342.571832 -228.014022)
		(end 342.216232 -228.014022)
		(width 0.088646)
		(layer "In6.Cu")
		(net "M_C_CPU0_SB_DQS_DP<3>")
	)
	(segment
		(start 292.639242 -198.564246)
		(end 290.47948 -199.459088)
		(width 0.18288)
		(layer "In6.Cu")
		(net "M_C_CPU0_SB_DQS_DP<3>")
	)
	(segment
		(start 307.023516 -199.776334)
		(end 301.91964 -199.776334)
		(width 0.18288)
		(layer "In6.Cu")
		(net "M_C_CPU0_SB_DQS_DP<3>")
	)
	(segment
		(start 334.958182 -225.69297)
		(end 334.947768 -225.699066)
		(width 0.088646)
		(layer "In6.Cu")
		(net "M_C_CPU0_SB_DQS_DP<3>")
	)
	(segment
		(start 295.082976 -199.4408)
		(end 294.720518 -199.4408)
		(width 0.18288)
		(layer "In6.Cu")
		(net "M_C_CPU0_SB_DQS_DP<3>")
	)
	(segment
		(start 298.342812 -198.32574)
		(end 296.312082 -199.166988)
		(width 0.18288)
		(layer "In6.Cu")
		(net "M_C_CPU0_SB_DQS_DP<3>")
	)
	(segment
		(start 334.018636 -225.69297)
		(end 334.008222 -225.699066)
		(width 0.088646)
		(layer "In6.Cu")
		(net "M_C_CPU0_SB_DQS_DP<3>")
	)
	(segment
		(start 340.040468 -227.325682)
		(end 340.031578 -227.320602)
		(width 0.088646)
		(layer "In6.Cu")
		(net "M_C_CPU0_SB_DQS_DP<3>")
	)
	(segment
		(start 332.396084 -225.603562)
		(end 332.39583 -225.603054)
		(width 0.088646)
		(layer "In6.Cu")
		(net "M_C_CPU0_SB_DQS_DP<3>")
	)
	(segment
		(start 340.21903 -227.659184)
		(end 340.21903 -227.64496)
		(width 0.088646)
		(layer "In6.Cu")
		(net "M_C_CPU0_SB_DQS_DP<3>")
	)
	(segment
		(start 280.60142 -200.434702)
		(end 280.098754 -200.434702)
		(width 0.18288)
		(layer "In6.Cu")
		(net "M_C_CPU0_SB_DQS_DP<3>")
	)
	(segment
		(start 327.879456 -220.105732)
		(end 319.27927 -211.505546)
		(width 0.18288)
		(layer "In6.Cu")
		(net "M_C_CPU0_SB_DQS_DP<3>")
	)
	(segment
		(start 319.27927 -211.505546)
		(end 317.19139 -206.421482)
		(width 0.18288)
		(layer "In6.Cu")
		(net "M_C_CPU0_SB_DQS_DP<3>")
	)
	(segment
		(start 283.448506 -200.870566)
		(end 282.695142 -200.870566)
		(width 0.18288)
		(layer "In6.Cu")
		(net "M_C_CPU0_SB_DQS_DP<3>")
	)
	(segment
		(start 287.542224 -199.4535)
		(end 287.179766 -199.4535)
		(width 0.18288)
		(layer "In6.Cu")
		(net "M_C_CPU0_SB_DQS_DP<3>")
	)
	(arc
		(start 334.393032 -225.69297)
		(mid 334.205834 -225.642827)
		(end 334.018636 -225.69297)
		(width 0.088646)
		(layer "In6.Cu")
		(net "M_C_CPU0_SB_DQS_DP<3>")
	)
	(arc
		(start 342.838278 -227.976684)
		(mid 342.739436 -228.014194)
		(end 342.633808 -228.01834)
		(width 0.088646)
		(layer "In6.Cu")
		(net "M_C_CPU0_SB_DQS_DP<3>")
	)
	(arc
		(start 335.79054 -226.499674)
		(mid 335.592312 -226.293826)
		(end 335.52003 -226.017328)
		(width 0.088646)
		(layer "In6.Cu")
		(net "M_C_CPU0_SB_DQS_DP<3>")
	)
	(arc
		(start 335.98993 -226.822508)
		(mid 335.93766 -226.640143)
		(end 335.802732 -226.506786)
		(width 0.088646)
		(layer "In6.Cu")
		(net "M_C_CPU0_SB_DQS_DP<3>")
	)
	(arc
		(start 340.21903 -227.64496)
		(mid 340.171351 -227.46206)
		(end 340.040468 -227.325682)
		(width 0.088646)
		(layer "In6.Cu")
		(net "M_C_CPU0_SB_DQS_DP<3>")
	)
	(arc
		(start 337.777836 -227.320602)
		(mid 337.503637 -227.396437)
		(end 337.227164 -227.329238)
		(width 0.088646)
		(layer "In6.Cu")
		(net "M_C_CPU0_SB_DQS_DP<3>")
	)
	(arc
		(start 341.992712 -228.1428)
		(mid 341.716047 -228.210271)
		(end 341.441532 -228.134418)
		(width 0.088646)
		(layer "In6.Cu")
		(net "M_C_CPU0_SB_DQS_DP<3>")
	)
	(arc
		(start 339.092032 -227.320602)
		(mid 338.904834 -227.270459)
		(end 338.717636 -227.320602)
		(width 0.088646)
		(layer "In6.Cu")
		(net "M_C_CPU0_SB_DQS_DP<3>")
	)
	(arc
		(start 339.646768 -227.326698)
		(mid 339.36859 -227.396421)
		(end 339.092032 -227.320602)
		(width 0.088646)
		(layer "In6.Cu")
		(net "M_C_CPU0_SB_DQS_DP<3>")
	)
	(arc
		(start 334.947768 -225.699066)
		(mid 334.66959 -225.768758)
		(end 334.393032 -225.69297)
		(width 0.088646)
		(layer "In6.Cu")
		(net "M_C_CPU0_SB_DQS_DP<3>")
	)
	(arc
		(start 332.512924 -225.692208)
		(mid 332.503344 -225.686585)
		(end 332.493874 -225.680778)
		(width 0.088646)
		(layer "In6.Cu")
		(net "M_C_CPU0_SB_DQS_DP<3>")
	)
	(arc
		(start 341.441278 -228.134672)
		(mid 341.25408 -228.084529)
		(end 341.066882 -228.134672)
		(width 0.088646)
		(layer "In6.Cu")
		(net "M_C_CPU0_SB_DQS_DP<3>")
	)
	(arc
		(start 338.152232 -227.320602)
		(mid 337.965034 -227.270459)
		(end 337.777836 -227.320602)
		(width 0.088646)
		(layer "In6.Cu")
		(net "M_C_CPU0_SB_DQS_DP<3>")
	)
	(arc
		(start 340.031578 -227.320602)
		(mid 339.84438 -227.270459)
		(end 339.657182 -227.320602)
		(width 0.088646)
		(layer "In6.Cu")
		(net "M_C_CPU0_SB_DQS_DP<3>")
	)
	(arc
		(start 337.212432 -227.320602)
		(mid 337.025234 -227.270459)
		(end 336.838036 -227.320602)
		(width 0.088646)
		(layer "In6.Cu")
		(net "M_C_CPU0_SB_DQS_DP<3>")
	)
	(arc
		(start 336.838036 -227.320602)
		(mid 336.563837 -227.396437)
		(end 336.287364 -227.329238)
		(width 0.088646)
		(layer "In6.Cu")
		(net "M_C_CPU0_SB_DQS_DP<3>")
	)
	(arc
		(start 341.05215 -228.143308)
		(mid 340.775709 -228.210474)
		(end 340.501478 -228.134672)
		(width 0.088646)
		(layer "In6.Cu")
		(net "M_C_CPU0_SB_DQS_DP<3>")
	)
	(arc
		(start 335.332578 -225.69297)
		(mid 335.14538 -225.642827)
		(end 334.958182 -225.69297)
		(width 0.088646)
		(layer "In6.Cu")
		(net "M_C_CPU0_SB_DQS_DP<3>")
	)
	(arc
		(start 333.060548 -225.703384)
		(mid 332.785301 -225.768505)
		(end 332.512924 -225.692208)
		(width 0.088646)
		(layer "In6.Cu")
		(net "M_C_CPU0_SB_DQS_DP<3>")
	)
	(arc
		(start 333.452978 -225.69297)
		(mid 333.26578 -225.642827)
		(end 333.078582 -225.69297)
		(width 0.088646)
		(layer "In6.Cu")
		(net "M_C_CPU0_SB_DQS_DP<3>")
	)
	(arc
		(start 332.493874 -225.680778)
		(mid 332.442845 -225.644872)
		(end 332.396084 -225.603562)
		(width 0.088646)
		(layer "In6.Cu")
		(net "M_C_CPU0_SB_DQS_DP<3>")
	)
	(arc
		(start 334.008222 -225.699066)
		(mid 333.72979 -225.76888)
		(end 333.452978 -225.69297)
		(width 0.088646)
		(layer "In6.Cu")
		(net "M_C_CPU0_SB_DQS_DP<3>")
	)
	(arc
		(start 343.603834 -227.64496)
		(mid 343.427813 -227.667797)
		(end 343.263474 -227.734876)
		(width 0.088646)
		(layer "In6.Cu")
		(net "M_C_CPU0_SB_DQS_DP<3>")
	)
	(arc
		(start 335.52003 -226.017328)
		(mid 335.472351 -225.834428)
		(end 335.341468 -225.69805)
		(width 0.088646)
		(layer "In6.Cu")
		(net "M_C_CPU0_SB_DQS_DP<3>")
	)
	(arc
		(start 336.266536 -227.317046)
		(mid 336.063949 -227.110695)
		(end 335.98993 -226.831144)
		(width 0.088646)
		(layer "In6.Cu")
		(net "M_C_CPU0_SB_DQS_DP<3>")
	)
	(arc
		(start 340.501478 -228.134672)
		(mid 340.298173 -227.933806)
		(end 340.21903 -227.659184)
		(width 0.088646)
		(layer "In6.Cu")
		(net "M_C_CPU0_SB_DQS_DP<3>")
	)
	(arc
		(start 338.717636 -227.320602)
		(mid 338.443437 -227.396437)
		(end 338.166964 -227.329238)
		(width 0.088646)
		(layer "In6.Cu")
		(net "M_C_CPU0_SB_DQS_DP<3>")
	)
	(segment
		(start 274.143978 -210.50123)
		(end 273.925792 -210.50123)
		(width 0.20066)
		(layer "F.Cu")
		(net "M_C_CPU0_SB_DQS_DP<2>")
	)
	(segment
		(start 273.925792 -210.50123)
		(end 273.655282 -210.23072)
		(width 0.20066)
		(layer "F.Cu")
		(net "M_C_CPU0_SB_DQS_DP<2>")
	)
	(segment
		(start 277.902162 -209.805524)
		(end 277.63343 -209.805524)
		(width 0.20066)
		(layer "F.Cu")
		(net "M_C_CPU0_SB_DQS_DP<2>")
	)
	(segment
		(start 278.163274 -210.066636)
		(end 277.902162 -209.805524)
		(width 0.20066)
		(layer "F.Cu")
		(net "M_C_CPU0_SB_DQS_DP<2>")
	)
	(segment
		(start 274.390358 -210.491832)
		(end 274.153376 -210.491832)
		(width 0.101854)
		(layer "F.Cu")
		(net "M_C_CPU0_SB_DQS_DP<2>")
	)
	(segment
		(start 273.028156 -210.23072)
		(end 272.39214 -209.805524)
		(width 0.20066)
		(layer "F.Cu")
		(net "M_C_CPU0_SB_DQS_DP<2>")
	)
	(segment
		(start 277.208234 -210.23072)
		(end 276.882352 -210.23072)
		(width 0.20066)
		(layer "F.Cu")
		(net "M_C_CPU0_SB_DQS_DP<2>")
	)
	(segment
		(start 278.711914 -210.066636)
		(end 278.163274 -210.066636)
		(width 0.20066)
		(layer "F.Cu")
		(net "M_C_CPU0_SB_DQS_DP<2>")
	)
	(segment
		(start 271.967198 -209.805524)
		(end 271.706086 -210.066636)
		(width 0.20066)
		(layer "F.Cu")
		(net "M_C_CPU0_SB_DQS_DP<2>")
	)
	(segment
		(start 276.145752 -210.491832)
		(end 274.390358 -210.491832)
		(width 0.1016)
		(layer "F.Cu")
		(net "M_C_CPU0_SB_DQS_DP<2>")
	)
	(segment
		(start 340.314534 -230.086916)
		(end 340.31428 -230.086662)
		(width 0.20066)
		(layer "F.Cu")
		(net "M_C_CPU0_SB_DQS_DP<2>")
	)
	(segment
		(start 272.39214 -209.805524)
		(end 271.967198 -209.805524)
		(width 0.20066)
		(layer "F.Cu")
		(net "M_C_CPU0_SB_DQS_DP<2>")
	)
	(segment
		(start 271.706086 -210.066636)
		(end 271.168114 -210.066636)
		(width 0.20066)
		(layer "F.Cu")
		(net "M_C_CPU0_SB_DQS_DP<2>")
	)
	(segment
		(start 276.62124 -210.491832)
		(end 276.469094 -210.491832)
		(width 0.20066)
		(layer "F.Cu")
		(net "M_C_CPU0_SB_DQS_DP<2>")
	)
	(segment
		(start 277.63343 -209.805524)
		(end 277.208234 -210.23072)
		(width 0.20066)
		(layer "F.Cu")
		(net "M_C_CPU0_SB_DQS_DP<2>")
	)
	(segment
		(start 276.469094 -210.491832)
		(end 276.145752 -210.491832)
		(width 0.101854)
		(layer "F.Cu")
		(net "M_C_CPU0_SB_DQS_DP<2>")
	)
	(segment
		(start 279.816814 -210.066636)
		(end 278.711914 -210.066636)
		(width 0.20066)
		(layer "F.Cu")
		(net "M_C_CPU0_SB_DQS_DP<2>")
	)
	(segment
		(start 340.314534 -230.622602)
		(end 340.314534 -230.086916)
		(width 0.20066)
		(layer "F.Cu")
		(net "M_C_CPU0_SB_DQS_DP<2>")
	)
	(segment
		(start 276.882352 -210.23072)
		(end 276.62124 -210.491832)
		(width 0.20066)
		(layer "F.Cu")
		(net "M_C_CPU0_SB_DQS_DP<2>")
	)
	(segment
		(start 273.655282 -210.23072)
		(end 273.028156 -210.23072)
		(width 0.20066)
		(layer "F.Cu")
		(net "M_C_CPU0_SB_DQS_DP<2>")
	)
	(segment
		(start 274.153376 -210.491832)
		(end 274.143978 -210.50123)
		(width 0.101854)
		(layer "F.Cu")
		(net "M_C_CPU0_SB_DQS_DP<2>")
	)
	(segment
		(start 338.151978 -230.57612)
		(end 338.152232 -230.57612)
		(width 0.088646)
		(layer "In4.Cu")
		(net "M_C_CPU0_SB_DQS_DP<2>")
	)
	(segment
		(start 292.374828 -211.995512)
		(end 291.464746 -211.08543)
		(width 0.18288)
		(layer "In4.Cu")
		(net "M_C_CPU0_SB_DQS_DP<2>")
	)
	(segment
		(start 299.43425 -211.934044)
		(end 299.17644 -212.191854)
		(width 0.18288)
		(layer "In4.Cu")
		(net "M_C_CPU0_SB_DQS_DP<2>")
	)
	(segment
		(start 283.71546 -210.491832)
		(end 283.440124 -210.216496)
		(width 0.18288)
		(layer "In4.Cu")
		(net "M_C_CPU0_SB_DQS_DP<2>")
	)
	(segment
		(start 314.323984 -212.77961)
		(end 312.048144 -212.77961)
		(width 0.18288)
		(layer "In4.Cu")
		(net "M_C_CPU0_SB_DQS_DP<2>")
	)
	(segment
		(start 299.17644 -212.191854)
		(end 298.808648 -212.191854)
		(width 0.18288)
		(layer "In4.Cu")
		(net "M_C_CPU0_SB_DQS_DP<2>")
	)
	(segment
		(start 314.545472 -213.001352)
		(end 314.323984 -212.77961)
		(width 0.18288)
		(layer "In4.Cu")
		(net "M_C_CPU0_SB_DQS_DP<2>")
	)
	(segment
		(start 331.33411 -229.752906)
		(end 331.004926 -229.423722)
		(width 0.088646)
		(layer "In4.Cu")
		(net "M_C_CPU0_SB_DQS_DP<2>")
	)
	(segment
		(start 297.386502 -212.77453)
		(end 295.359582 -212.77453)
		(width 0.18288)
		(layer "In4.Cu")
		(net "M_C_CPU0_SB_DQS_DP<2>")
	)
	(segment
		(start 281.024838 -209.580988)
		(end 280.820622 -209.785204)
		(width 0.18288)
		(layer "In4.Cu")
		(net "M_C_CPU0_SB_DQS_DP<2>")
	)
	(segment
		(start 292.993826 -211.995512)
		(end 292.374828 -211.995512)
		(width 0.18288)
		(layer "In4.Cu")
		(net "M_C_CPU0_SB_DQS_DP<2>")
	)
	(segment
		(start 333.467964 -230.584756)
		(end 333.453232 -230.57612)
		(width 0.088646)
		(layer "In4.Cu")
		(net "M_C_CPU0_SB_DQS_DP<2>")
	)
	(segment
		(start 309.90921 -211.893912)
		(end 307.549296 -211.893912)
		(width 0.18288)
		(layer "In4.Cu")
		(net "M_C_CPU0_SB_DQS_DP<2>")
	)
	(segment
		(start 315.328046 -214.889842)
		(end 315.3283 -214.889842)
		(width 0.18288)
		(layer "In4.Cu")
		(net "M_C_CPU0_SB_DQS_DP<2>")
	)
	(segment
		(start 294.70858 -213.041992)
		(end 294.432736 -212.766148)
		(width 0.18288)
		(layer "In4.Cu")
		(net "M_C_CPU0_SB_DQS_DP<2>")
	)
	(segment
		(start 335.347564 -230.584756)
		(end 335.332832 -230.57612)
		(width 0.088646)
		(layer "In4.Cu")
		(net "M_C_CPU0_SB_DQS_DP<2>")
	)
	(segment
		(start 337.227164 -230.584756)
		(end 337.212432 -230.57612)
		(width 0.088646)
		(layer "In4.Cu")
		(net "M_C_CPU0_SB_DQS_DP<2>")
	)
	(segment
		(start 312.048144 -212.77961)
		(end 309.90921 -211.893912)
		(width 0.18288)
		(layer "In4.Cu")
		(net "M_C_CPU0_SB_DQS_DP<2>")
	)
	(segment
		(start 298.808648 -212.191854)
		(end 298.533312 -211.916518)
		(width 0.18288)
		(layer "In4.Cu")
		(net "M_C_CPU0_SB_DQS_DP<2>")
	)
	(segment
		(start 334.407764 -230.584756)
		(end 334.393032 -230.57612)
		(width 0.088646)
		(layer "In4.Cu")
		(net "M_C_CPU0_SB_DQS_DP<2>")
	)
	(segment
		(start 330.671932 -229.483666)
		(end 330.648564 -229.483666)
		(width 0.088646)
		(layer "In4.Cu")
		(net "M_C_CPU0_SB_DQS_DP<2>")
	)
	(segment
		(start 293.764462 -212.766148)
		(end 292.993826 -211.995512)
		(width 0.18288)
		(layer "In4.Cu")
		(net "M_C_CPU0_SB_DQS_DP<2>")
	)
	(segment
		(start 338.926678 -230.455724)
		(end 338.703158 -230.584502)
		(width 0.088646)
		(layer "In4.Cu")
		(net "M_C_CPU0_SB_DQS_DP<2>")
	)
	(segment
		(start 295.09212 -213.041992)
		(end 294.70858 -213.041992)
		(width 0.18288)
		(layer "In4.Cu")
		(net "M_C_CPU0_SB_DQS_DP<2>")
	)
	(segment
		(start 332.528164 -230.584756)
		(end 332.513432 -230.57612)
		(width 0.088646)
		(layer "In4.Cu")
		(net "M_C_CPU0_SB_DQS_DP<2>")
	)
	(segment
		(start 331.33411 -229.843584)
		(end 331.33411 -229.752906)
		(width 0.088646)
		(layer "In4.Cu")
		(net "M_C_CPU0_SB_DQS_DP<2>")
	)
	(segment
		(start 330.731876 -229.423722)
		(end 330.671932 -229.483666)
		(width 0.088646)
		(layer "In4.Cu")
		(net "M_C_CPU0_SB_DQS_DP<2>")
	)
	(segment
		(start 280.820622 -209.785204)
		(end 280.098246 -209.785204)
		(width 0.18288)
		(layer "In4.Cu")
		(net "M_C_CPU0_SB_DQS_DP<2>")
	)
	(segment
		(start 307.549296 -211.893912)
		(end 306.816252 -211.160868)
		(width 0.18288)
		(layer "In4.Cu")
		(net "M_C_CPU0_SB_DQS_DP<2>")
	)
	(segment
		(start 339.344254 -230.460042)
		(end 339.287104 -230.453184)
		(width 0.088646)
		(layer "In4.Cu")
		(net "M_C_CPU0_SB_DQS_DP<2>")
	)
	(segment
		(start 282.85313 -210.216496)
		(end 282.217622 -209.580988)
		(width 0.18288)
		(layer "In4.Cu")
		(net "M_C_CPU0_SB_DQS_DP<2>")
	)
	(segment
		(start 288.417 -211.08543)
		(end 287.559496 -210.227926)
		(width 0.18288)
		(layer "In4.Cu")
		(net "M_C_CPU0_SB_DQS_DP<2>")
	)
	(segment
		(start 306.816252 -211.160868)
		(end 303.741582 -211.160868)
		(width 0.18288)
		(layer "In4.Cu")
		(net "M_C_CPU0_SB_DQS_DP<2>")
	)
	(segment
		(start 315.3283 -214.889842)
		(end 314.545472 -213.001352)
		(width 0.18288)
		(layer "In4.Cu")
		(net "M_C_CPU0_SB_DQS_DP<2>")
	)
	(segment
		(start 298.533312 -211.916518)
		(end 298.244514 -211.916518)
		(width 0.18288)
		(layer "In4.Cu")
		(net "M_C_CPU0_SB_DQS_DP<2>")
	)
	(segment
		(start 325.518272 -229.483666)
		(end 318.444372 -222.409766)
		(width 0.18288)
		(layer "In4.Cu")
		(net "M_C_CPU0_SB_DQS_DP<2>")
	)
	(segment
		(start 291.464746 -211.08543)
		(end 288.417 -211.08543)
		(width 0.18288)
		(layer "In4.Cu")
		(net "M_C_CPU0_SB_DQS_DP<2>")
	)
	(segment
		(start 298.244514 -211.916518)
		(end 297.386502 -212.77453)
		(width 0.18288)
		(layer "In4.Cu")
		(net "M_C_CPU0_SB_DQS_DP<2>")
	)
	(segment
		(start 287.559496 -210.227926)
		(end 284.454346 -210.227926)
		(width 0.18288)
		(layer "In4.Cu")
		(net "M_C_CPU0_SB_DQS_DP<2>")
	)
	(segment
		(start 280.098246 -209.785204)
		(end 279.816814 -210.066636)
		(width 0.18288)
		(layer "In4.Cu")
		(net "M_C_CPU0_SB_DQS_DP<2>")
	)
	(segment
		(start 318.444372 -222.409766)
		(end 315.328046 -214.889842)
		(width 0.18288)
		(layer "In4.Cu")
		(net "M_C_CPU0_SB_DQS_DP<2>")
	)
	(segment
		(start 339.97392 -230.176578)
		(end 339.548724 -230.418386)
		(width 0.088646)
		(layer "In4.Cu")
		(net "M_C_CPU0_SB_DQS_DP<2>")
	)
	(segment
		(start 339.282278 -230.455724)
		(end 338.926678 -230.455724)
		(width 0.088646)
		(layer "In4.Cu")
		(net "M_C_CPU0_SB_DQS_DP<2>")
	)
	(segment
		(start 283.440124 -210.216496)
		(end 282.85313 -210.216496)
		(width 0.18288)
		(layer "In4.Cu")
		(net "M_C_CPU0_SB_DQS_DP<2>")
	)
	(segment
		(start 282.217622 -209.580988)
		(end 281.024838 -209.580988)
		(width 0.18288)
		(layer "In4.Cu")
		(net "M_C_CPU0_SB_DQS_DP<2>")
	)
	(segment
		(start 331.004926 -229.423722)
		(end 330.731876 -229.423722)
		(width 0.088646)
		(layer "In4.Cu")
		(net "M_C_CPU0_SB_DQS_DP<2>")
	)
	(segment
		(start 302.968406 -211.934044)
		(end 299.43425 -211.934044)
		(width 0.18288)
		(layer "In4.Cu")
		(net "M_C_CPU0_SB_DQS_DP<2>")
	)
	(segment
		(start 330.648564 -229.483666)
		(end 325.518272 -229.483666)
		(width 0.18288)
		(layer "In4.Cu")
		(net "M_C_CPU0_SB_DQS_DP<2>")
	)
	(segment
		(start 331.79512 -230.304594)
		(end 331.33411 -229.843584)
		(width 0.088646)
		(layer "In4.Cu")
		(net "M_C_CPU0_SB_DQS_DP<2>")
	)
	(segment
		(start 336.843624 -230.572818)
		(end 336.83321 -230.57866)
		(width 0.088646)
		(layer "In4.Cu")
		(net "M_C_CPU0_SB_DQS_DP<2>")
	)
	(segment
		(start 339.287104 -230.453184)
		(end 339.282278 -230.455724)
		(width 0.088646)
		(layer "In4.Cu")
		(net "M_C_CPU0_SB_DQS_DP<2>")
	)
	(segment
		(start 294.432736 -212.766148)
		(end 293.764462 -212.766148)
		(width 0.18288)
		(layer "In4.Cu")
		(net "M_C_CPU0_SB_DQS_DP<2>")
	)
	(segment
		(start 284.454346 -210.227926)
		(end 284.19044 -210.491832)
		(width 0.18288)
		(layer "In4.Cu")
		(net "M_C_CPU0_SB_DQS_DP<2>")
	)
	(segment
		(start 295.359582 -212.77453)
		(end 295.09212 -213.041992)
		(width 0.18288)
		(layer "In4.Cu")
		(net "M_C_CPU0_SB_DQS_DP<2>")
	)
	(segment
		(start 303.741582 -211.160868)
		(end 302.968406 -211.934044)
		(width 0.18288)
		(layer "In4.Cu")
		(net "M_C_CPU0_SB_DQS_DP<2>")
	)
	(segment
		(start 284.19044 -210.491832)
		(end 283.71546 -210.491832)
		(width 0.18288)
		(layer "In4.Cu")
		(net "M_C_CPU0_SB_DQS_DP<2>")
	)
	(arc
		(start 333.078836 -230.57612)
		(mid 332.804637 -230.651955)
		(end 332.528164 -230.584756)
		(width 0.088646)
		(layer "In4.Cu")
		(net "M_C_CPU0_SB_DQS_DP<2>")
	)
	(arc
		(start 334.958436 -230.57612)
		(mid 334.684237 -230.651955)
		(end 334.407764 -230.584756)
		(width 0.088646)
		(layer "In4.Cu")
		(net "M_C_CPU0_SB_DQS_DP<2>")
	)
	(arc
		(start 338.152232 -230.57612)
		(mid 337.965034 -230.525977)
		(end 337.777836 -230.57612)
		(width 0.088646)
		(layer "In4.Cu")
		(net "M_C_CPU0_SB_DQS_DP<2>")
	)
	(arc
		(start 340.31428 -230.086662)
		(mid 340.138259 -230.109499)
		(end 339.97392 -230.176578)
		(width 0.088646)
		(layer "In4.Cu")
		(net "M_C_CPU0_SB_DQS_DP<2>")
	)
	(arc
		(start 332.50886 -230.57358)
		(mid 332.420987 -230.538002)
		(end 332.326996 -230.525574)
		(width 0.088646)
		(layer "In4.Cu")
		(net "M_C_CPU0_SB_DQS_DP<2>")
	)
	(arc
		(start 337.777836 -230.57612)
		(mid 337.503637 -230.651955)
		(end 337.227164 -230.584756)
		(width 0.088646)
		(layer "In4.Cu")
		(net "M_C_CPU0_SB_DQS_DP<2>")
	)
	(arc
		(start 334.018636 -230.57612)
		(mid 333.744437 -230.651955)
		(end 333.467964 -230.584756)
		(width 0.088646)
		(layer "In4.Cu")
		(net "M_C_CPU0_SB_DQS_DP<2>")
	)
	(arc
		(start 339.548724 -230.418386)
		(mid 339.449882 -230.455896)
		(end 339.344254 -230.460042)
		(width 0.088646)
		(layer "In4.Cu")
		(net "M_C_CPU0_SB_DQS_DP<2>")
	)
	(arc
		(start 338.703158 -230.584502)
		(mid 338.426493 -230.651973)
		(end 338.151978 -230.57612)
		(width 0.088646)
		(layer "In4.Cu")
		(net "M_C_CPU0_SB_DQS_DP<2>")
	)
	(arc
		(start 333.453232 -230.57612)
		(mid 333.266034 -230.525977)
		(end 333.078836 -230.57612)
		(width 0.088646)
		(layer "In4.Cu")
		(net "M_C_CPU0_SB_DQS_DP<2>")
	)
	(arc
		(start 334.393032 -230.57612)
		(mid 334.205834 -230.525977)
		(end 334.018636 -230.57612)
		(width 0.088646)
		(layer "In4.Cu")
		(net "M_C_CPU0_SB_DQS_DP<2>")
	)
	(arc
		(start 335.332832 -230.57612)
		(mid 335.145634 -230.525977)
		(end 334.958436 -230.57612)
		(width 0.088646)
		(layer "In4.Cu")
		(net "M_C_CPU0_SB_DQS_DP<2>")
	)
	(arc
		(start 337.212432 -230.57612)
		(mid 337.028478 -230.525991)
		(end 336.843624 -230.572818)
		(width 0.088646)
		(layer "In4.Cu")
		(net "M_C_CPU0_SB_DQS_DP<2>")
	)
	(arc
		(start 335.898236 -230.57612)
		(mid 335.624037 -230.651955)
		(end 335.347564 -230.584756)
		(width 0.088646)
		(layer "In4.Cu")
		(net "M_C_CPU0_SB_DQS_DP<2>")
	)
	(arc
		(start 332.513432 -230.57612)
		(mid 332.51115 -230.574842)
		(end 332.50886 -230.57358)
		(width 0.088646)
		(layer "In4.Cu")
		(net "M_C_CPU0_SB_DQS_DP<2>")
	)
	(arc
		(start 336.272632 -230.57612)
		(mid 336.085434 -230.525977)
		(end 335.898236 -230.57612)
		(width 0.088646)
		(layer "In4.Cu")
		(net "M_C_CPU0_SB_DQS_DP<2>")
	)
	(arc
		(start 336.83321 -230.57866)
		(mid 336.552575 -230.651828)
		(end 336.272632 -230.57612)
		(width 0.088646)
		(layer "In4.Cu")
		(net "M_C_CPU0_SB_DQS_DP<2>")
	)
	(arc
		(start 332.326996 -230.525574)
		(mid 332.039191 -230.46774)
		(end 331.79512 -230.304594)
		(width 0.088646)
		(layer "In4.Cu")
		(net "M_C_CPU0_SB_DQS_DP<2>")
	)
	(segment
		(start 273.925792 -219.851224)
		(end 273.655282 -219.580714)
		(width 0.20066)
		(layer "F.Cu")
		(net "M_C_CPU0_SB_DQS_DP<1>")
	)
	(segment
		(start 276.62124 -219.841826)
		(end 276.469094 -219.841826)
		(width 0.20066)
		(layer "F.Cu")
		(net "M_C_CPU0_SB_DQS_DP<1>")
	)
	(segment
		(start 276.882352 -219.580714)
		(end 276.62124 -219.841826)
		(width 0.20066)
		(layer "F.Cu")
		(net "M_C_CPU0_SB_DQS_DP<1>")
	)
	(segment
		(start 278.711914 -219.41663)
		(end 278.163274 -219.41663)
		(width 0.20066)
		(layer "F.Cu")
		(net "M_C_CPU0_SB_DQS_DP<1>")
	)
	(segment
		(start 274.143978 -219.851224)
		(end 273.925792 -219.851224)
		(width 0.20066)
		(layer "F.Cu")
		(net "M_C_CPU0_SB_DQS_DP<1>")
	)
	(segment
		(start 278.163274 -219.41663)
		(end 277.902162 -219.155518)
		(width 0.20066)
		(layer "F.Cu")
		(net "M_C_CPU0_SB_DQS_DP<1>")
	)
	(segment
		(start 271.967198 -219.155518)
		(end 271.706086 -219.41663)
		(width 0.20066)
		(layer "F.Cu")
		(net "M_C_CPU0_SB_DQS_DP<1>")
	)
	(segment
		(start 277.902162 -219.155518)
		(end 277.63343 -219.155518)
		(width 0.20066)
		(layer "F.Cu")
		(net "M_C_CPU0_SB_DQS_DP<1>")
	)
	(segment
		(start 277.208234 -219.580714)
		(end 276.882352 -219.580714)
		(width 0.20066)
		(layer "F.Cu")
		(net "M_C_CPU0_SB_DQS_DP<1>")
	)
	(segment
		(start 274.390358 -219.841826)
		(end 274.153376 -219.841826)
		(width 0.101854)
		(layer "F.Cu")
		(net "M_C_CPU0_SB_DQS_DP<1>")
	)
	(segment
		(start 343.60358 -237.947454)
		(end 343.603834 -237.9472)
		(width 0.20066)
		(layer "F.Cu")
		(net "M_C_CPU0_SB_DQS_DP<1>")
	)
	(segment
		(start 276.469094 -219.841826)
		(end 276.145752 -219.841826)
		(width 0.101854)
		(layer "F.Cu")
		(net "M_C_CPU0_SB_DQS_DP<1>")
	)
	(segment
		(start 279.816814 -219.41663)
		(end 278.711914 -219.41663)
		(width 0.20066)
		(layer "F.Cu")
		(net "M_C_CPU0_SB_DQS_DP<1>")
	)
	(segment
		(start 343.603834 -237.9472)
		(end 343.603834 -237.411514)
		(width 0.20066)
		(layer "F.Cu")
		(net "M_C_CPU0_SB_DQS_DP<1>")
	)
	(segment
		(start 276.145752 -219.841826)
		(end 274.390358 -219.841826)
		(width 0.1016)
		(layer "F.Cu")
		(net "M_C_CPU0_SB_DQS_DP<1>")
	)
	(segment
		(start 272.39214 -219.155518)
		(end 271.967198 -219.155518)
		(width 0.20066)
		(layer "F.Cu")
		(net "M_C_CPU0_SB_DQS_DP<1>")
	)
	(segment
		(start 271.706086 -219.41663)
		(end 271.168114 -219.41663)
		(width 0.20066)
		(layer "F.Cu")
		(net "M_C_CPU0_SB_DQS_DP<1>")
	)
	(segment
		(start 273.028156 -219.580714)
		(end 272.39214 -219.155518)
		(width 0.20066)
		(layer "F.Cu")
		(net "M_C_CPU0_SB_DQS_DP<1>")
	)
	(segment
		(start 277.63343 -219.155518)
		(end 277.208234 -219.580714)
		(width 0.20066)
		(layer "F.Cu")
		(net "M_C_CPU0_SB_DQS_DP<1>")
	)
	(segment
		(start 274.153376 -219.841826)
		(end 274.143978 -219.851224)
		(width 0.101854)
		(layer "F.Cu")
		(net "M_C_CPU0_SB_DQS_DP<1>")
	)
	(segment
		(start 273.655282 -219.580714)
		(end 273.028156 -219.580714)
		(width 0.20066)
		(layer "F.Cu")
		(net "M_C_CPU0_SB_DQS_DP<1>")
	)
	(segment
		(start 312.975244 -226.366832)
		(end 312.283856 -225.675444)
		(width 0.18288)
		(layer "In6.Cu")
		(net "M_C_CPU0_SB_DQS_DP<1>")
	)
	(segment
		(start 342.571832 -237.780576)
		(end 342.216232 -237.780576)
		(width 0.088646)
		(layer "In6.Cu")
		(net "M_C_CPU0_SB_DQS_DP<1>")
	)
	(segment
		(start 314.567316 -226.356418)
		(end 314.283344 -226.64039)
		(width 0.18288)
		(layer "In6.Cu")
		(net "M_C_CPU0_SB_DQS_DP<1>")
	)
	(segment
		(start 342.633808 -237.784894)
		(end 342.576658 -237.778036)
		(width 0.088646)
		(layer "In6.Cu")
		(net "M_C_CPU0_SB_DQS_DP<1>")
	)
	(segment
		(start 293.006272 -221.529656)
		(end 292.555422 -221.529656)
		(width 0.18288)
		(layer "In6.Cu")
		(net "M_C_CPU0_SB_DQS_DP<1>")
	)
	(segment
		(start 308.081172 -222.97517)
		(end 306.629308 -222.373698)
		(width 0.18288)
		(layer "In6.Cu")
		(net "M_C_CPU0_SB_DQS_DP<1>")
	)
	(segment
		(start 284.427168 -219.583762)
		(end 284.168596 -219.842334)
		(width 0.18288)
		(layer "In6.Cu")
		(net "M_C_CPU0_SB_DQS_DP<1>")
	)
	(segment
		(start 295.425876 -222.132652)
		(end 295.165018 -222.39351)
		(width 0.18288)
		(layer "In6.Cu")
		(net "M_C_CPU0_SB_DQS_DP<1>")
	)
	(segment
		(start 303.283366 -222.373698)
		(end 302.707802 -222.949262)
		(width 0.18288)
		(layer "In6.Cu")
		(net "M_C_CPU0_SB_DQS_DP<1>")
	)
	(segment
		(start 284.168596 -219.842334)
		(end 283.671264 -219.842334)
		(width 0.18288)
		(layer "In6.Cu")
		(net "M_C_CPU0_SB_DQS_DP<1>")
	)
	(segment
		(start 280.092404 -219.14104)
		(end 279.816814 -219.41663)
		(width 0.18288)
		(layer "In6.Cu")
		(net "M_C_CPU0_SB_DQS_DP<1>")
	)
	(segment
		(start 299.24375 -223.24441)
		(end 298.79163 -223.24441)
		(width 0.18288)
		(layer "In6.Cu")
		(net "M_C_CPU0_SB_DQS_DP<1>")
	)
	(segment
		(start 310.272938 -223.196658)
		(end 309.73776 -222.97517)
		(width 0.18288)
		(layer "In6.Cu")
		(net "M_C_CPU0_SB_DQS_DP<1>")
	)
	(segment
		(start 331.441298 -236.666532)
		(end 331.441298 -236.318552)
		(width 0.088646)
		(layer "In6.Cu")
		(net "M_C_CPU0_SB_DQS_DP<1>")
	)
	(segment
		(start 298.492926 -222.945706)
		(end 298.067984 -222.945706)
		(width 0.18288)
		(layer "In6.Cu")
		(net "M_C_CPU0_SB_DQS_DP<1>")
	)
	(segment
		(start 336.367882 -237.901226)
		(end 336.357468 -237.907322)
		(width 0.088646)
		(layer "In6.Cu")
		(net "M_C_CPU0_SB_DQS_DP<1>")
	)
	(segment
		(start 338.247482 -237.901226)
		(end 338.23275 -237.909862)
		(width 0.088646)
		(layer "In6.Cu")
		(net "M_C_CPU0_SB_DQS_DP<1>")
	)
	(segment
		(start 331.362304 -236.239558)
		(end 331.362304 -235.782612)
		(width 0.088646)
		(layer "In6.Cu")
		(net "M_C_CPU0_SB_DQS_DP<1>")
	)
	(segment
		(start 297.255438 -222.132652)
		(end 295.425876 -222.132652)
		(width 0.18288)
		(layer "In6.Cu")
		(net "M_C_CPU0_SB_DQS_DP<1>")
	)
	(segment
		(start 294.392858 -222.116142)
		(end 293.925244 -222.116142)
		(width 0.18288)
		(layer "In6.Cu")
		(net "M_C_CPU0_SB_DQS_DP<1>")
	)
	(segment
		(start 283.671264 -219.842334)
		(end 283.395166 -219.566236)
		(width 0.18288)
		(layer "In6.Cu")
		(net "M_C_CPU0_SB_DQS_DP<1>")
	)
	(segment
		(start 314.83427 -226.356418)
		(end 314.567316 -226.356418)
		(width 0.18288)
		(layer "In6.Cu")
		(net "M_C_CPU0_SB_DQS_DP<1>")
	)
	(segment
		(start 287.435798 -219.583762)
		(end 284.427168 -219.583762)
		(width 0.18288)
		(layer "In6.Cu")
		(net "M_C_CPU0_SB_DQS_DP<1>")
	)
	(segment
		(start 293.573962 -221.76486)
		(end 293.006272 -221.529656)
		(width 0.18288)
		(layer "In6.Cu")
		(net "M_C_CPU0_SB_DQS_DP<1>")
	)
	(segment
		(start 331.362304 -235.782612)
		(end 331.03566 -235.455968)
		(width 0.088646)
		(layer "In6.Cu")
		(net "M_C_CPU0_SB_DQS_DP<1>")
	)
	(segment
		(start 294.670226 -222.39351)
		(end 294.392858 -222.116142)
		(width 0.18288)
		(layer "In6.Cu")
		(net "M_C_CPU0_SB_DQS_DP<1>")
	)
	(segment
		(start 289.27171 -220.345)
		(end 287.435798 -219.583762)
		(width 0.18288)
		(layer "In6.Cu")
		(net "M_C_CPU0_SB_DQS_DP<1>")
	)
	(segment
		(start 309.73776 -222.97517)
		(end 308.081172 -222.97517)
		(width 0.18288)
		(layer "In6.Cu")
		(net "M_C_CPU0_SB_DQS_DP<1>")
	)
	(segment
		(start 334.873092 -237.907322)
		(end 334.862678 -237.901226)
		(width 0.088646)
		(layer "In6.Cu")
		(net "M_C_CPU0_SB_DQS_DP<1>")
	)
	(segment
		(start 312.283856 -225.675444)
		(end 311.589166 -225.387662)
		(width 0.18288)
		(layer "In6.Cu")
		(net "M_C_CPU0_SB_DQS_DP<1>")
	)
	(segment
		(start 291.743384 -221.865952)
		(end 291.149786 -221.865952)
		(width 0.18288)
		(layer "In6.Cu")
		(net "M_C_CPU0_SB_DQS_DP<1>")
	)
	(segment
		(start 339.187536 -237.901226)
		(end 339.177122 -237.907322)
		(width 0.088646)
		(layer "In6.Cu")
		(net "M_C_CPU0_SB_DQS_DP<1>")
	)
	(segment
		(start 315.106304 -226.628452)
		(end 314.83427 -226.356418)
		(width 0.18288)
		(layer "In6.Cu")
		(net "M_C_CPU0_SB_DQS_DP<1>")
	)
	(segment
		(start 342.576658 -237.778036)
		(end 342.571832 -237.780576)
		(width 0.088646)
		(layer "In6.Cu")
		(net "M_C_CPU0_SB_DQS_DP<1>")
	)
	(segment
		(start 283.395166 -219.566236)
		(end 282.952952 -219.566236)
		(width 0.18288)
		(layer "In6.Cu")
		(net "M_C_CPU0_SB_DQS_DP<1>")
	)
	(segment
		(start 293.925244 -222.116142)
		(end 293.573962 -221.76486)
		(width 0.18288)
		(layer "In6.Cu")
		(net "M_C_CPU0_SB_DQS_DP<1>")
	)
	(segment
		(start 313.603132 -226.366832)
		(end 312.975244 -226.366832)
		(width 0.18288)
		(layer "In6.Cu")
		(net "M_C_CPU0_SB_DQS_DP<1>")
	)
	(segment
		(start 331.441298 -236.318552)
		(end 331.362304 -236.239558)
		(width 0.088646)
		(layer "In6.Cu")
		(net "M_C_CPU0_SB_DQS_DP<1>")
	)
	(segment
		(start 298.79163 -223.24441)
		(end 298.492926 -222.945706)
		(width 0.18288)
		(layer "In6.Cu")
		(net "M_C_CPU0_SB_DQS_DP<1>")
	)
	(segment
		(start 302.707802 -222.949262)
		(end 299.538898 -222.949262)
		(width 0.18288)
		(layer "In6.Cu")
		(net "M_C_CPU0_SB_DQS_DP<1>")
	)
	(segment
		(start 342.216232 -237.780576)
		(end 341.992712 -237.909354)
		(width 0.088646)
		(layer "In6.Cu")
		(net "M_C_CPU0_SB_DQS_DP<1>")
	)
	(segment
		(start 337.307682 -237.901226)
		(end 337.29295 -237.909862)
		(width 0.088646)
		(layer "In6.Cu")
		(net "M_C_CPU0_SB_DQS_DP<1>")
	)
	(segment
		(start 330.775564 -235.515912)
		(end 322.373498 -235.515912)
		(width 0.18288)
		(layer "In6.Cu")
		(net "M_C_CPU0_SB_DQS_DP<1>")
	)
	(segment
		(start 311.589166 -225.387662)
		(end 311.277254 -225.07575)
		(width 0.18288)
		(layer "In6.Cu")
		(net "M_C_CPU0_SB_DQS_DP<1>")
	)
	(segment
		(start 341.441532 -237.900972)
		(end 341.441278 -237.901226)
		(width 0.088646)
		(layer "In6.Cu")
		(net "M_C_CPU0_SB_DQS_DP<1>")
	)
	(segment
		(start 311.277254 -225.07575)
		(end 310.272938 -223.196658)
		(width 0.18288)
		(layer "In6.Cu")
		(net "M_C_CPU0_SB_DQS_DP<1>")
	)
	(segment
		(start 280.42235 -219.14104)
		(end 280.092404 -219.14104)
		(width 0.18288)
		(layer "In6.Cu")
		(net "M_C_CPU0_SB_DQS_DP<1>")
	)
	(segment
		(start 280.910792 -218.938856)
		(end 280.42235 -219.14104)
		(width 0.18288)
		(layer "In6.Cu")
		(net "M_C_CPU0_SB_DQS_DP<1>")
	)
	(segment
		(start 331.899768 -237.125002)
		(end 331.441298 -236.666532)
		(width 0.088646)
		(layer "In6.Cu")
		(net "M_C_CPU0_SB_DQS_DP<1>")
	)
	(segment
		(start 322.373498 -235.515912)
		(end 315.106304 -228.248718)
		(width 0.18288)
		(layer "In6.Cu")
		(net "M_C_CPU0_SB_DQS_DP<1>")
	)
	(segment
		(start 339.572346 -237.907322)
		(end 339.561932 -237.901226)
		(width 0.088646)
		(layer "In6.Cu")
		(net "M_C_CPU0_SB_DQS_DP<1>")
	)
	(segment
		(start 292.555422 -221.529656)
		(end 291.743384 -221.865952)
		(width 0.18288)
		(layer "In6.Cu")
		(net "M_C_CPU0_SB_DQS_DP<1>")
	)
	(segment
		(start 330.858876 -235.455968)
		(end 330.798932 -235.515912)
		(width 0.088646)
		(layer "In6.Cu")
		(net "M_C_CPU0_SB_DQS_DP<1>")
	)
	(segment
		(start 298.067984 -222.945706)
		(end 297.255438 -222.132652)
		(width 0.18288)
		(layer "In6.Cu")
		(net "M_C_CPU0_SB_DQS_DP<1>")
	)
	(segment
		(start 330.798932 -235.515912)
		(end 330.775564 -235.515912)
		(width 0.088646)
		(layer "In6.Cu")
		(net "M_C_CPU0_SB_DQS_DP<1>")
	)
	(segment
		(start 282.325572 -218.938856)
		(end 280.910792 -218.938856)
		(width 0.18288)
		(layer "In6.Cu")
		(net "M_C_CPU0_SB_DQS_DP<1>")
	)
	(segment
		(start 315.106304 -228.248718)
		(end 315.106304 -226.628452)
		(width 0.18288)
		(layer "In6.Cu")
		(net "M_C_CPU0_SB_DQS_DP<1>")
	)
	(segment
		(start 295.165018 -222.39351)
		(end 294.670226 -222.39351)
		(width 0.18288)
		(layer "In6.Cu")
		(net "M_C_CPU0_SB_DQS_DP<1>")
	)
	(segment
		(start 299.538898 -222.949262)
		(end 299.24375 -223.24441)
		(width 0.18288)
		(layer "In6.Cu")
		(net "M_C_CPU0_SB_DQS_DP<1>")
	)
	(segment
		(start 291.149786 -221.865952)
		(end 290.538916 -221.612714)
		(width 0.18288)
		(layer "In6.Cu")
		(net "M_C_CPU0_SB_DQS_DP<1>")
	)
	(segment
		(start 306.629308 -222.373698)
		(end 303.283366 -222.373698)
		(width 0.18288)
		(layer "In6.Cu")
		(net "M_C_CPU0_SB_DQS_DP<1>")
	)
	(segment
		(start 341.066882 -237.901226)
		(end 341.05215 -237.909862)
		(width 0.088646)
		(layer "In6.Cu")
		(net "M_C_CPU0_SB_DQS_DP<1>")
	)
	(segment
		(start 290.538916 -221.612714)
		(end 289.27171 -220.345)
		(width 0.18288)
		(layer "In6.Cu")
		(net "M_C_CPU0_SB_DQS_DP<1>")
	)
	(segment
		(start 333.078582 -237.08741)
		(end 333.06385 -237.096046)
		(width 0.088646)
		(layer "In6.Cu")
		(net "M_C_CPU0_SB_DQS_DP<1>")
	)
	(segment
		(start 332.049882 -237.125002)
		(end 331.899768 -237.125002)
		(width 0.088646)
		(layer "In6.Cu")
		(net "M_C_CPU0_SB_DQS_DP<1>")
	)
	(segment
		(start 343.263474 -237.50143)
		(end 342.838278 -237.743238)
		(width 0.088646)
		(layer "In6.Cu")
		(net "M_C_CPU0_SB_DQS_DP<1>")
	)
	(segment
		(start 314.283344 -226.64039)
		(end 313.87669 -226.64039)
		(width 0.18288)
		(layer "In6.Cu")
		(net "M_C_CPU0_SB_DQS_DP<1>")
	)
	(segment
		(start 331.03566 -235.455968)
		(end 330.858876 -235.455968)
		(width 0.088646)
		(layer "In6.Cu")
		(net "M_C_CPU0_SB_DQS_DP<1>")
	)
	(segment
		(start 313.87669 -226.64039)
		(end 313.603132 -226.366832)
		(width 0.18288)
		(layer "In6.Cu")
		(net "M_C_CPU0_SB_DQS_DP<1>")
	)
	(segment
		(start 282.952952 -219.566236)
		(end 282.325572 -218.938856)
		(width 0.18288)
		(layer "In6.Cu")
		(net "M_C_CPU0_SB_DQS_DP<1>")
	)
	(arc
		(start 342.838278 -237.743238)
		(mid 342.739436 -237.780748)
		(end 342.633808 -237.784894)
		(width 0.088646)
		(layer "In6.Cu")
		(net "M_C_CPU0_SB_DQS_DP<1>")
	)
	(arc
		(start 340.501478 -237.901226)
		(mid 340.31428 -237.851083)
		(end 340.127082 -237.901226)
		(width 0.088646)
		(layer "In6.Cu")
		(net "M_C_CPU0_SB_DQS_DP<1>")
	)
	(arc
		(start 337.682078 -237.901226)
		(mid 337.49488 -237.851083)
		(end 337.307682 -237.901226)
		(width 0.088646)
		(layer "In6.Cu")
		(net "M_C_CPU0_SB_DQS_DP<1>")
	)
	(arc
		(start 332.145894 -237.083346)
		(mid 332.098854 -237.1064)
		(end 332.049882 -237.125002)
		(width 0.088646)
		(layer "In6.Cu")
		(net "M_C_CPU0_SB_DQS_DP<1>")
	)
	(arc
		(start 340.127082 -237.901226)
		(mid 339.850523 -237.976969)
		(end 339.572346 -237.907322)
		(width 0.088646)
		(layer "In6.Cu")
		(net "M_C_CPU0_SB_DQS_DP<1>")
	)
	(arc
		(start 336.357468 -237.907322)
		(mid 336.07929 -237.977014)
		(end 335.802732 -237.901226)
		(width 0.088646)
		(layer "In6.Cu")
		(net "M_C_CPU0_SB_DQS_DP<1>")
	)
	(arc
		(start 333.64043 -237.411768)
		(mid 333.453131 -237.087327)
		(end 333.078582 -237.08741)
		(width 0.088646)
		(layer "In6.Cu")
		(net "M_C_CPU0_SB_DQS_DP<1>")
	)
	(arc
		(start 338.23275 -237.909862)
		(mid 337.956275 -237.977182)
		(end 337.682078 -237.901226)
		(width 0.088646)
		(layer "In6.Cu")
		(net "M_C_CPU0_SB_DQS_DP<1>")
	)
	(arc
		(start 335.428336 -237.901226)
		(mid 335.151523 -237.977096)
		(end 334.873092 -237.907322)
		(width 0.088646)
		(layer "In6.Cu")
		(net "M_C_CPU0_SB_DQS_DP<1>")
	)
	(arc
		(start 334.488282 -237.901226)
		(mid 333.923005 -237.9013)
		(end 333.64043 -237.411768)
		(width 0.088646)
		(layer "In6.Cu")
		(net "M_C_CPU0_SB_DQS_DP<1>")
	)
	(arc
		(start 341.441278 -237.901226)
		(mid 341.25408 -237.851083)
		(end 341.066882 -237.901226)
		(width 0.088646)
		(layer "In6.Cu")
		(net "M_C_CPU0_SB_DQS_DP<1>")
	)
	(arc
		(start 341.992712 -237.909354)
		(mid 341.716047 -237.976825)
		(end 341.441532 -237.900972)
		(width 0.088646)
		(layer "In6.Cu")
		(net "M_C_CPU0_SB_DQS_DP<1>")
	)
	(arc
		(start 332.513178 -237.08741)
		(mid 332.330075 -237.037289)
		(end 332.145894 -237.083346)
		(width 0.088646)
		(layer "In6.Cu")
		(net "M_C_CPU0_SB_DQS_DP<1>")
	)
	(arc
		(start 339.561932 -237.901226)
		(mid 339.374734 -237.851083)
		(end 339.187536 -237.901226)
		(width 0.088646)
		(layer "In6.Cu")
		(net "M_C_CPU0_SB_DQS_DP<1>")
	)
	(arc
		(start 333.06385 -237.096046)
		(mid 332.787375 -237.163366)
		(end 332.513178 -237.08741)
		(width 0.088646)
		(layer "In6.Cu")
		(net "M_C_CPU0_SB_DQS_DP<1>")
	)
	(arc
		(start 338.621878 -237.901226)
		(mid 338.43468 -237.851083)
		(end 338.247482 -237.901226)
		(width 0.088646)
		(layer "In6.Cu")
		(net "M_C_CPU0_SB_DQS_DP<1>")
	)
	(arc
		(start 334.862678 -237.901226)
		(mid 334.67548 -237.851083)
		(end 334.488282 -237.901226)
		(width 0.088646)
		(layer "In6.Cu")
		(net "M_C_CPU0_SB_DQS_DP<1>")
	)
	(arc
		(start 341.05215 -237.909862)
		(mid 340.775709 -237.977028)
		(end 340.501478 -237.901226)
		(width 0.088646)
		(layer "In6.Cu")
		(net "M_C_CPU0_SB_DQS_DP<1>")
	)
	(arc
		(start 337.29295 -237.909862)
		(mid 337.016509 -237.977028)
		(end 336.742278 -237.901226)
		(width 0.088646)
		(layer "In6.Cu")
		(net "M_C_CPU0_SB_DQS_DP<1>")
	)
	(arc
		(start 339.177122 -237.907322)
		(mid 338.89869 -237.977168)
		(end 338.621878 -237.901226)
		(width 0.088646)
		(layer "In6.Cu")
		(net "M_C_CPU0_SB_DQS_DP<1>")
	)
	(arc
		(start 343.603834 -237.411514)
		(mid 343.427813 -237.434351)
		(end 343.263474 -237.50143)
		(width 0.088646)
		(layer "In6.Cu")
		(net "M_C_CPU0_SB_DQS_DP<1>")
	)
	(arc
		(start 336.742278 -237.901226)
		(mid 336.55508 -237.851083)
		(end 336.367882 -237.901226)
		(width 0.088646)
		(layer "In6.Cu")
		(net "M_C_CPU0_SB_DQS_DP<1>")
	)
	(arc
		(start 335.802732 -237.901226)
		(mid 335.615534 -237.851083)
		(end 335.428336 -237.901226)
		(width 0.088646)
		(layer "In6.Cu")
		(net "M_C_CPU0_SB_DQS_DP<1>")
	)
	(segment
		(start 271.706086 -228.766624)
		(end 271.168114 -228.766624)
		(width 0.20066)
		(layer "F.Cu")
		(net "M_C_CPU0_SB_DQS_DP<0>")
	)
	(segment
		(start 276.882352 -228.930708)
		(end 276.62124 -229.19182)
		(width 0.20066)
		(layer "F.Cu")
		(net "M_C_CPU0_SB_DQS_DP<0>")
	)
	(segment
		(start 277.902162 -228.505512)
		(end 277.63343 -228.505512)
		(width 0.20066)
		(layer "F.Cu")
		(net "M_C_CPU0_SB_DQS_DP<0>")
	)
	(segment
		(start 273.925792 -229.201218)
		(end 273.655282 -228.930708)
		(width 0.20066)
		(layer "F.Cu")
		(net "M_C_CPU0_SB_DQS_DP<0>")
	)
	(segment
		(start 278.711914 -228.766624)
		(end 278.163274 -228.766624)
		(width 0.20066)
		(layer "F.Cu")
		(net "M_C_CPU0_SB_DQS_DP<0>")
	)
	(segment
		(start 273.027902 -228.930708)
		(end 272.392902 -228.505512)
		(width 0.20066)
		(layer "F.Cu")
		(net "M_C_CPU0_SB_DQS_DP<0>")
	)
	(segment
		(start 271.967198 -228.505512)
		(end 271.706086 -228.766624)
		(width 0.20066)
		(layer "F.Cu")
		(net "M_C_CPU0_SB_DQS_DP<0>")
	)
	(segment
		(start 274.153376 -229.19182)
		(end 274.144232 -229.200964)
		(width 0.101854)
		(layer "F.Cu")
		(net "M_C_CPU0_SB_DQS_DP<0>")
	)
	(segment
		(start 274.390358 -229.19182)
		(end 274.153376 -229.19182)
		(width 0.101854)
		(layer "F.Cu")
		(net "M_C_CPU0_SB_DQS_DP<0>")
	)
	(segment
		(start 276.469348 -229.19182)
		(end 276.145752 -229.19182)
		(width 0.101854)
		(layer "F.Cu")
		(net "M_C_CPU0_SB_DQS_DP<0>")
	)
	(segment
		(start 279.816814 -228.766624)
		(end 278.711914 -228.766624)
		(width 0.20066)
		(layer "F.Cu")
		(net "M_C_CPU0_SB_DQS_DP<0>")
	)
	(segment
		(start 272.392902 -228.505512)
		(end 271.967198 -228.505512)
		(width 0.20066)
		(layer "F.Cu")
		(net "M_C_CPU0_SB_DQS_DP<0>")
	)
	(segment
		(start 276.145752 -229.19182)
		(end 274.390358 -229.19182)
		(width 0.1016)
		(layer "F.Cu")
		(net "M_C_CPU0_SB_DQS_DP<0>")
	)
	(segment
		(start 276.62124 -229.19182)
		(end 276.469348 -229.19182)
		(width 0.20066)
		(layer "F.Cu")
		(net "M_C_CPU0_SB_DQS_DP<0>")
	)
	(segment
		(start 277.208234 -228.930708)
		(end 276.882352 -228.930708)
		(width 0.20066)
		(layer "F.Cu")
		(net "M_C_CPU0_SB_DQS_DP<0>")
	)
	(segment
		(start 277.63343 -228.505512)
		(end 277.208234 -228.930708)
		(width 0.20066)
		(layer "F.Cu")
		(net "M_C_CPU0_SB_DQS_DP<0>")
	)
	(segment
		(start 273.655282 -228.930708)
		(end 273.027902 -228.930708)
		(width 0.20066)
		(layer "F.Cu")
		(net "M_C_CPU0_SB_DQS_DP<0>")
	)
	(segment
		(start 343.60358 -242.830858)
		(end 343.603834 -242.294918)
		(width 0.20066)
		(layer "F.Cu")
		(net "M_C_CPU0_SB_DQS_DP<0>")
	)
	(segment
		(start 278.163274 -228.766624)
		(end 277.902162 -228.505512)
		(width 0.20066)
		(layer "F.Cu")
		(net "M_C_CPU0_SB_DQS_DP<0>")
	)
	(segment
		(start 274.143978 -229.201218)
		(end 273.925792 -229.201218)
		(width 0.20066)
		(layer "F.Cu")
		(net "M_C_CPU0_SB_DQS_DP<0>")
	)
	(segment
		(start 274.144232 -229.200964)
		(end 274.143978 -229.201218)
		(width 0.20066)
		(layer "F.Cu")
		(net "M_C_CPU0_SB_DQS_DP<0>")
	)
	(segment
		(start 302.726852 -234.021884)
		(end 299.554392 -234.021884)
		(width 0.18288)
		(layer "In6.Cu")
		(net "M_C_CPU0_SB_DQS_DP<0>")
	)
	(segment
		(start 297.247818 -233.170476)
		(end 295.427908 -233.170476)
		(width 0.18288)
		(layer "In6.Cu")
		(net "M_C_CPU0_SB_DQS_DP<0>")
	)
	(segment
		(start 331.283056 -241.376708)
		(end 331.112876 -241.376708)
		(width 0.088646)
		(layer "In6.Cu")
		(net "M_C_CPU0_SB_DQS_DP<0>")
	)
	(segment
		(start 311.552082 -236.360462)
		(end 310.081422 -235.749846)
		(width 0.18288)
		(layer "In6.Cu")
		(net "M_C_CPU0_SB_DQS_DP<0>")
	)
	(segment
		(start 338.247482 -242.78463)
		(end 338.23275 -242.793266)
		(width 0.088646)
		(layer "In6.Cu")
		(net "M_C_CPU0_SB_DQS_DP<0>")
	)
	(segment
		(start 284.197298 -229.191566)
		(end 283.718762 -229.191566)
		(width 0.18288)
		(layer "In6.Cu")
		(net "M_C_CPU0_SB_DQS_DP<0>")
	)
	(segment
		(start 294.678608 -233.441748)
		(end 294.392858 -233.155998)
		(width 0.18288)
		(layer "In6.Cu")
		(net "M_C_CPU0_SB_DQS_DP<0>")
	)
	(segment
		(start 282.830524 -228.90607)
		(end 282.368498 -228.444044)
		(width 0.18288)
		(layer "In6.Cu")
		(net "M_C_CPU0_SB_DQS_DP<0>")
	)
	(segment
		(start 331.052932 -241.436652)
		(end 331.029564 -241.436652)
		(width 0.088646)
		(layer "In6.Cu")
		(net "M_C_CPU0_SB_DQS_DP<0>")
	)
	(segment
		(start 341.441532 -242.784376)
		(end 341.441278 -242.78463)
		(width 0.088646)
		(layer "In6.Cu")
		(net "M_C_CPU0_SB_DQS_DP<0>")
	)
	(segment
		(start 310.081422 -235.749846)
		(end 307.707284 -235.749846)
		(width 0.18288)
		(layer "In6.Cu")
		(net "M_C_CPU0_SB_DQS_DP<0>")
	)
	(segment
		(start 283.718762 -229.191566)
		(end 283.433266 -228.90607)
		(width 0.18288)
		(layer "In6.Cu")
		(net "M_C_CPU0_SB_DQS_DP<0>")
	)
	(segment
		(start 298.520866 -234.005882)
		(end 298.083224 -234.005882)
		(width 0.18288)
		(layer "In6.Cu")
		(net "M_C_CPU0_SB_DQS_DP<0>")
	)
	(segment
		(start 331.112876 -241.376708)
		(end 331.052932 -241.436652)
		(width 0.088646)
		(layer "In6.Cu")
		(net "M_C_CPU0_SB_DQS_DP<0>")
	)
	(segment
		(start 342.576658 -242.66144)
		(end 342.571832 -242.66398)
		(width 0.088646)
		(layer "In6.Cu")
		(net "M_C_CPU0_SB_DQS_DP<0>")
	)
	(segment
		(start 331.926184 -242.694714)
		(end 331.753972 -242.522502)
		(width 0.088646)
		(layer "In6.Cu")
		(net "M_C_CPU0_SB_DQS_DP<0>")
	)
	(segment
		(start 299.554392 -234.021884)
		(end 299.284644 -234.291632)
		(width 0.18288)
		(layer "In6.Cu")
		(net "M_C_CPU0_SB_DQS_DP<0>")
	)
	(segment
		(start 287.90392 -230.356918)
		(end 286.68726 -230.356918)
		(width 0.18288)
		(layer "In6.Cu")
		(net "M_C_CPU0_SB_DQS_DP<0>")
	)
	(segment
		(start 303.456086 -234.751118)
		(end 302.726852 -234.021884)
		(width 0.18288)
		(layer "In6.Cu")
		(net "M_C_CPU0_SB_DQS_DP<0>")
	)
	(segment
		(start 299.284644 -234.291632)
		(end 298.806616 -234.291632)
		(width 0.18288)
		(layer "In6.Cu")
		(net "M_C_CPU0_SB_DQS_DP<0>")
	)
	(segment
		(start 341.066882 -242.78463)
		(end 341.05215 -242.793266)
		(width 0.088646)
		(layer "In6.Cu")
		(net "M_C_CPU0_SB_DQS_DP<0>")
	)
	(segment
		(start 298.083224 -234.005882)
		(end 297.247818 -233.170476)
		(width 0.18288)
		(layer "In6.Cu")
		(net "M_C_CPU0_SB_DQS_DP<0>")
	)
	(segment
		(start 336.367882 -242.78463)
		(end 336.357468 -242.790726)
		(width 0.088646)
		(layer "In6.Cu")
		(net "M_C_CPU0_SB_DQS_DP<0>")
	)
	(segment
		(start 342.633808 -242.668298)
		(end 342.576658 -242.66144)
		(width 0.088646)
		(layer "In6.Cu")
		(net "M_C_CPU0_SB_DQS_DP<0>")
	)
	(segment
		(start 331.029564 -241.436652)
		(end 319.226692 -241.436652)
		(width 0.18288)
		(layer "In6.Cu")
		(net "M_C_CPU0_SB_DQS_DP<0>")
	)
	(segment
		(start 281.23134 -228.229414)
		(end 280.613866 -228.485192)
		(width 0.18288)
		(layer "In6.Cu")
		(net "M_C_CPU0_SB_DQS_DP<0>")
	)
	(segment
		(start 295.156636 -233.441748)
		(end 294.678608 -233.441748)
		(width 0.18288)
		(layer "In6.Cu")
		(net "M_C_CPU0_SB_DQS_DP<0>")
	)
	(segment
		(start 280.613866 -228.485192)
		(end 280.098246 -228.485192)
		(width 0.18288)
		(layer "In6.Cu")
		(net "M_C_CPU0_SB_DQS_DP<0>")
	)
	(segment
		(start 332.998064 -242.793266)
		(end 332.983332 -242.78463)
		(width 0.088646)
		(layer "In6.Cu")
		(net "M_C_CPU0_SB_DQS_DP<0>")
	)
	(segment
		(start 288.75482 -231.207818)
		(end 287.90392 -230.356918)
		(width 0.18288)
		(layer "In6.Cu")
		(net "M_C_CPU0_SB_DQS_DP<0>")
	)
	(segment
		(start 285.242254 -228.911912)
		(end 284.476952 -228.911912)
		(width 0.18288)
		(layer "In6.Cu")
		(net "M_C_CPU0_SB_DQS_DP<0>")
	)
	(segment
		(start 342.216232 -242.66398)
		(end 341.992712 -242.792758)
		(width 0.088646)
		(layer "In6.Cu")
		(net "M_C_CPU0_SB_DQS_DP<0>")
	)
	(segment
		(start 314.945014 -237.154974)
		(end 313.313572 -237.154974)
		(width 0.18288)
		(layer "In6.Cu")
		(net "M_C_CPU0_SB_DQS_DP<0>")
	)
	(segment
		(start 312.51906 -236.360462)
		(end 311.552082 -236.360462)
		(width 0.18288)
		(layer "In6.Cu")
		(net "M_C_CPU0_SB_DQS_DP<0>")
	)
	(segment
		(start 319.226692 -241.436652)
		(end 314.945014 -237.154974)
		(width 0.18288)
		(layer "In6.Cu")
		(net "M_C_CPU0_SB_DQS_DP<0>")
	)
	(segment
		(start 294.392858 -233.155998)
		(end 293.468044 -233.155998)
		(width 0.18288)
		(layer "In6.Cu")
		(net "M_C_CPU0_SB_DQS_DP<0>")
	)
	(segment
		(start 283.433266 -228.90607)
		(end 282.830524 -228.90607)
		(width 0.18288)
		(layer "In6.Cu")
		(net "M_C_CPU0_SB_DQS_DP<0>")
	)
	(segment
		(start 339.572346 -242.790726)
		(end 339.561932 -242.78463)
		(width 0.088646)
		(layer "In6.Cu")
		(net "M_C_CPU0_SB_DQS_DP<0>")
	)
	(segment
		(start 313.313572 -237.154974)
		(end 312.51906 -236.360462)
		(width 0.18288)
		(layer "In6.Cu")
		(net "M_C_CPU0_SB_DQS_DP<0>")
	)
	(segment
		(start 280.098246 -228.485192)
		(end 279.816814 -228.766624)
		(width 0.18288)
		(layer "In6.Cu")
		(net "M_C_CPU0_SB_DQS_DP<0>")
	)
	(segment
		(start 282.368498 -228.444044)
		(end 281.850338 -228.229414)
		(width 0.18288)
		(layer "In6.Cu")
		(net "M_C_CPU0_SB_DQS_DP<0>")
	)
	(segment
		(start 298.806616 -234.291632)
		(end 298.520866 -234.005882)
		(width 0.18288)
		(layer "In6.Cu")
		(net "M_C_CPU0_SB_DQS_DP<0>")
	)
	(segment
		(start 292.212014 -231.899968)
		(end 290.542726 -231.207818)
		(width 0.18288)
		(layer "In6.Cu")
		(net "M_C_CPU0_SB_DQS_DP<0>")
	)
	(segment
		(start 284.476952 -228.911912)
		(end 284.197298 -229.191566)
		(width 0.18288)
		(layer "In6.Cu")
		(net "M_C_CPU0_SB_DQS_DP<0>")
	)
	(segment
		(start 295.427908 -233.170476)
		(end 295.156636 -233.441748)
		(width 0.18288)
		(layer "In6.Cu")
		(net "M_C_CPU0_SB_DQS_DP<0>")
	)
	(segment
		(start 334.877664 -242.793266)
		(end 334.862932 -242.78463)
		(width 0.088646)
		(layer "In6.Cu")
		(net "M_C_CPU0_SB_DQS_DP<0>")
	)
	(segment
		(start 331.753972 -242.522502)
		(end 331.753972 -241.847624)
		(width 0.088646)
		(layer "In6.Cu")
		(net "M_C_CPU0_SB_DQS_DP<0>")
	)
	(segment
		(start 342.571832 -242.66398)
		(end 342.216232 -242.66398)
		(width 0.088646)
		(layer "In6.Cu")
		(net "M_C_CPU0_SB_DQS_DP<0>")
	)
	(segment
		(start 281.850338 -228.229414)
		(end 281.23134 -228.229414)
		(width 0.18288)
		(layer "In6.Cu")
		(net "M_C_CPU0_SB_DQS_DP<0>")
	)
	(segment
		(start 290.542726 -231.207818)
		(end 288.75482 -231.207818)
		(width 0.18288)
		(layer "In6.Cu")
		(net "M_C_CPU0_SB_DQS_DP<0>")
	)
	(segment
		(start 343.263474 -242.384834)
		(end 342.838278 -242.626642)
		(width 0.088646)
		(layer "In6.Cu")
		(net "M_C_CPU0_SB_DQS_DP<0>")
	)
	(segment
		(start 286.68726 -230.356918)
		(end 285.242254 -228.911912)
		(width 0.18288)
		(layer "In6.Cu")
		(net "M_C_CPU0_SB_DQS_DP<0>")
	)
	(segment
		(start 339.187536 -242.78463)
		(end 339.177122 -242.790726)
		(width 0.088646)
		(layer "In6.Cu")
		(net "M_C_CPU0_SB_DQS_DP<0>")
	)
	(segment
		(start 337.307682 -242.78463)
		(end 337.29295 -242.793266)
		(width 0.088646)
		(layer "In6.Cu")
		(net "M_C_CPU0_SB_DQS_DP<0>")
	)
	(segment
		(start 331.753972 -241.847624)
		(end 331.283056 -241.376708)
		(width 0.088646)
		(layer "In6.Cu")
		(net "M_C_CPU0_SB_DQS_DP<0>")
	)
	(segment
		(start 293.468044 -233.155998)
		(end 292.212014 -231.899968)
		(width 0.18288)
		(layer "In6.Cu")
		(net "M_C_CPU0_SB_DQS_DP<0>")
	)
	(segment
		(start 307.707284 -235.749846)
		(end 306.708556 -234.751118)
		(width 0.18288)
		(layer "In6.Cu")
		(net "M_C_CPU0_SB_DQS_DP<0>")
	)
	(segment
		(start 306.708556 -234.751118)
		(end 303.456086 -234.751118)
		(width 0.18288)
		(layer "In6.Cu")
		(net "M_C_CPU0_SB_DQS_DP<0>")
	)
	(arc
		(start 336.742278 -242.78463)
		(mid 336.55508 -242.734487)
		(end 336.367882 -242.78463)
		(width 0.088646)
		(layer "In6.Cu")
		(net "M_C_CPU0_SB_DQS_DP<0>")
	)
	(arc
		(start 337.29295 -242.793266)
		(mid 337.016475 -242.860586)
		(end 336.742278 -242.78463)
		(width 0.088646)
		(layer "In6.Cu")
		(net "M_C_CPU0_SB_DQS_DP<0>")
	)
	(arc
		(start 333.923132 -242.78463)
		(mid 333.735934 -242.734487)
		(end 333.548736 -242.78463)
		(width 0.088646)
		(layer "In6.Cu")
		(net "M_C_CPU0_SB_DQS_DP<0>")
	)
	(arc
		(start 338.23275 -242.793266)
		(mid 337.956275 -242.860586)
		(end 337.682078 -242.78463)
		(width 0.088646)
		(layer "In6.Cu")
		(net "M_C_CPU0_SB_DQS_DP<0>")
	)
	(arc
		(start 332.983332 -242.78463)
		(mid 332.796134 -242.734487)
		(end 332.608936 -242.78463)
		(width 0.088646)
		(layer "In6.Cu")
		(net "M_C_CPU0_SB_DQS_DP<0>")
	)
	(arc
		(start 334.488536 -242.78463)
		(mid 334.205834 -242.860372)
		(end 333.923132 -242.78463)
		(width 0.088646)
		(layer "In6.Cu")
		(net "M_C_CPU0_SB_DQS_DP<0>")
	)
	(arc
		(start 341.441278 -242.78463)
		(mid 341.25408 -242.734487)
		(end 341.066882 -242.78463)
		(width 0.088646)
		(layer "In6.Cu")
		(net "M_C_CPU0_SB_DQS_DP<0>")
	)
	(arc
		(start 341.05215 -242.793266)
		(mid 340.775709 -242.860432)
		(end 340.501478 -242.78463)
		(width 0.088646)
		(layer "In6.Cu")
		(net "M_C_CPU0_SB_DQS_DP<0>")
	)
	(arc
		(start 337.682078 -242.78463)
		(mid 337.49488 -242.734487)
		(end 337.307682 -242.78463)
		(width 0.088646)
		(layer "In6.Cu")
		(net "M_C_CPU0_SB_DQS_DP<0>")
	)
	(arc
		(start 340.501478 -242.78463)
		(mid 340.31428 -242.734487)
		(end 340.127082 -242.78463)
		(width 0.088646)
		(layer "In6.Cu")
		(net "M_C_CPU0_SB_DQS_DP<0>")
	)
	(arc
		(start 339.561932 -242.78463)
		(mid 339.374734 -242.734487)
		(end 339.187536 -242.78463)
		(width 0.088646)
		(layer "In6.Cu")
		(net "M_C_CPU0_SB_DQS_DP<0>")
	)
	(arc
		(start 333.548736 -242.78463)
		(mid 333.274507 -242.860555)
		(end 332.998064 -242.793266)
		(width 0.088646)
		(layer "In6.Cu")
		(net "M_C_CPU0_SB_DQS_DP<0>")
	)
	(arc
		(start 332.608936 -242.78463)
		(mid 332.252324 -242.855521)
		(end 331.926184 -242.694714)
		(width 0.088646)
		(layer "In6.Cu")
		(net "M_C_CPU0_SB_DQS_DP<0>")
	)
	(arc
		(start 336.357468 -242.790726)
		(mid 336.07929 -242.860449)
		(end 335.802732 -242.78463)
		(width 0.088646)
		(layer "In6.Cu")
		(net "M_C_CPU0_SB_DQS_DP<0>")
	)
	(arc
		(start 341.992712 -242.792758)
		(mid 341.716047 -242.860229)
		(end 341.441532 -242.784376)
		(width 0.088646)
		(layer "In6.Cu")
		(net "M_C_CPU0_SB_DQS_DP<0>")
	)
	(arc
		(start 335.802732 -242.78463)
		(mid 335.615534 -242.734487)
		(end 335.428336 -242.78463)
		(width 0.088646)
		(layer "In6.Cu")
		(net "M_C_CPU0_SB_DQS_DP<0>")
	)
	(arc
		(start 340.127082 -242.78463)
		(mid 339.850523 -242.860373)
		(end 339.572346 -242.790726)
		(width 0.088646)
		(layer "In6.Cu")
		(net "M_C_CPU0_SB_DQS_DP<0>")
	)
	(arc
		(start 334.862932 -242.78463)
		(mid 334.675734 -242.734487)
		(end 334.488536 -242.78463)
		(width 0.088646)
		(layer "In6.Cu")
		(net "M_C_CPU0_SB_DQS_DP<0>")
	)
	(arc
		(start 338.621878 -242.78463)
		(mid 338.43468 -242.734487)
		(end 338.247482 -242.78463)
		(width 0.088646)
		(layer "In6.Cu")
		(net "M_C_CPU0_SB_DQS_DP<0>")
	)
	(arc
		(start 339.177122 -242.790726)
		(mid 338.89869 -242.860572)
		(end 338.621878 -242.78463)
		(width 0.088646)
		(layer "In6.Cu")
		(net "M_C_CPU0_SB_DQS_DP<0>")
	)
	(arc
		(start 342.838278 -242.626642)
		(mid 342.739436 -242.664152)
		(end 342.633808 -242.668298)
		(width 0.088646)
		(layer "In6.Cu")
		(net "M_C_CPU0_SB_DQS_DP<0>")
	)
	(arc
		(start 343.603834 -242.294918)
		(mid 343.427813 -242.317755)
		(end 343.263474 -242.384834)
		(width 0.088646)
		(layer "In6.Cu")
		(net "M_C_CPU0_SB_DQS_DP<0>")
	)
	(arc
		(start 335.428336 -242.78463)
		(mid 335.154107 -242.860555)
		(end 334.877664 -242.793266)
		(width 0.088646)
		(layer "In6.Cu")
		(net "M_C_CPU0_SB_DQS_DP<0>")
	)
	(segment
		(start 277.904194 -237.527846)
		(end 277.49754 -237.527846)
		(width 0.20066)
		(layer "F.Cu")
		(net "M_C_CPU0_SB_DQS_DN<9>")
	)
	(segment
		(start 277.49754 -237.527846)
		(end 277.072344 -237.953042)
		(width 0.20066)
		(layer "F.Cu")
		(net "M_C_CPU0_SB_DQS_DN<9>")
	)
	(segment
		(start 278.711914 -237.266734)
		(end 278.165306 -237.266734)
		(width 0.20066)
		(layer "F.Cu")
		(net "M_C_CPU0_SB_DQS_DN<9>")
	)
	(segment
		(start 273.678396 -237.953042)
		(end 273.127724 -237.953042)
		(width 0.20066)
		(layer "F.Cu")
		(net "M_C_CPU0_SB_DQS_DN<9>")
	)
	(segment
		(start 274.005802 -237.691676)
		(end 273.939762 -237.691676)
		(width 0.20066)
		(layer "F.Cu")
		(net "M_C_CPU0_SB_DQS_DN<9>")
	)
	(segment
		(start 279.816814 -237.266734)
		(end 278.711914 -237.266734)
		(width 0.20066)
		(layer "F.Cu")
		(net "M_C_CPU0_SB_DQS_DN<9>")
	)
	(segment
		(start 277.072344 -237.953042)
		(end 276.885654 -237.953042)
		(width 0.20066)
		(layer "F.Cu")
		(net "M_C_CPU0_SB_DQS_DN<9>")
	)
	(segment
		(start 272.491708 -237.527846)
		(end 271.977866 -237.527846)
		(width 0.20066)
		(layer "F.Cu")
		(net "M_C_CPU0_SB_DQS_DN<9>")
	)
	(segment
		(start 271.716754 -237.266734)
		(end 271.168114 -237.266734)
		(width 0.20066)
		(layer "F.Cu")
		(net "M_C_CPU0_SB_DQS_DN<9>")
	)
	(segment
		(start 276.624288 -237.691676)
		(end 276.530562 -237.691676)
		(width 0.20066)
		(layer "F.Cu")
		(net "M_C_CPU0_SB_DQS_DN<9>")
	)
	(segment
		(start 271.977866 -237.527846)
		(end 271.716754 -237.266734)
		(width 0.20066)
		(layer "F.Cu")
		(net "M_C_CPU0_SB_DQS_DN<9>")
	)
	(segment
		(start 278.165306 -237.266734)
		(end 277.904194 -237.527846)
		(width 0.20066)
		(layer "F.Cu")
		(net "M_C_CPU0_SB_DQS_DN<9>")
	)
	(segment
		(start 273.127724 -237.953042)
		(end 272.491708 -237.527846)
		(width 0.20066)
		(layer "F.Cu")
		(net "M_C_CPU0_SB_DQS_DN<9>")
	)
	(segment
		(start 276.469094 -237.691676)
		(end 274.155408 -237.691676)
		(width 0.1016)
		(layer "F.Cu")
		(net "M_C_CPU0_SB_DQS_DN<9>")
	)
	(segment
		(start 276.885654 -237.953042)
		(end 276.624288 -237.691676)
		(width 0.20066)
		(layer "F.Cu")
		(net "M_C_CPU0_SB_DQS_DN<9>")
	)
	(segment
		(start 276.530562 -237.691676)
		(end 276.469094 -237.691676)
		(width 0.101854)
		(layer "F.Cu")
		(net "M_C_CPU0_SB_DQS_DN<9>")
	)
	(segment
		(start 273.939762 -237.691676)
		(end 273.678396 -237.953042)
		(width 0.20066)
		(layer "F.Cu")
		(net "M_C_CPU0_SB_DQS_DN<9>")
	)
	(segment
		(start 339.374734 -239.85347)
		(end 339.37448 -239.853216)
		(width 0.20066)
		(layer "F.Cu")
		(net "M_C_CPU0_SB_DQS_DN<9>")
	)
	(segment
		(start 339.374734 -240.389156)
		(end 339.374734 -239.85347)
		(width 0.20066)
		(layer "F.Cu")
		(net "M_C_CPU0_SB_DQS_DN<9>")
	)
	(segment
		(start 274.155408 -237.691676)
		(end 274.005802 -237.691676)
		(width 0.101854)
		(layer "F.Cu")
		(net "M_C_CPU0_SB_DQS_DN<9>")
	)
	(segment
		(start 284.459426 -237.962694)
		(end 284.188408 -237.691676)
		(width 0.18288)
		(layer "In4.Cu")
		(net "M_C_CPU0_SB_DQS_DN<9>")
	)
	(segment
		(start 306.279042 -237.14456)
		(end 306.154582 -237.26902)
		(width 0.18288)
		(layer "In4.Cu")
		(net "M_C_CPU0_SB_DQS_DN<9>")
	)
	(segment
		(start 317.103252 -239.93602)
		(end 317.103252 -239.759998)
		(width 0.18288)
		(layer "In4.Cu")
		(net "M_C_CPU0_SB_DQS_DN<9>")
	)
	(segment
		(start 318.443102 -241.27587)
		(end 318.055244 -240.888012)
		(width 0.18288)
		(layer "In4.Cu")
		(net "M_C_CPU0_SB_DQS_DN<9>")
	)
	(segment
		(start 291.922454 -237.207806)
		(end 291.373814 -237.207806)
		(width 0.18288)
		(layer "In4.Cu")
		(net "M_C_CPU0_SB_DQS_DN<9>")
	)
	(segment
		(start 313.254644 -238.567468)
		(end 312.706004 -238.567468)
		(width 0.18288)
		(layer "In4.Cu")
		(net "M_C_CPU0_SB_DQS_DN<9>")
	)
	(segment
		(start 332.396338 -241.081052)
		(end 332.14183 -241.33556)
		(width 0.088646)
		(layer "In4.Cu")
		(net "M_C_CPU0_SB_DQS_DN<9>")
	)
	(segment
		(start 332.502764 -240.998502)
		(end 332.502002 -240.99901)
		(width 0.088646)
		(layer "In4.Cu")
		(net "M_C_CPU0_SB_DQS_DN<9>")
	)
	(segment
		(start 311.359804 -238.567468)
		(end 310.979312 -238.186976)
		(width 0.18288)
		(layer "In4.Cu")
		(net "M_C_CPU0_SB_DQS_DN<9>")
	)
	(segment
		(start 336.367882 -240.177574)
		(end 336.35315 -240.168938)
		(width 0.088646)
		(layer "In4.Cu")
		(net "M_C_CPU0_SB_DQS_DN<9>")
	)
	(segment
		(start 312.581544 -238.443008)
		(end 312.032904 -238.443008)
		(width 0.18288)
		(layer "In4.Cu")
		(net "M_C_CPU0_SB_DQS_DN<9>")
	)
	(segment
		(start 339.34273 -239.96904)
		(end 339.303868 -239.991138)
		(width 0.088646)
		(layer "In4.Cu")
		(net "M_C_CPU0_SB_DQS_DN<9>")
	)
	(segment
		(start 307.500782 -237.26902)
		(end 306.952142 -237.26902)
		(width 0.18288)
		(layer "In4.Cu")
		(net "M_C_CPU0_SB_DQS_DN<9>")
	)
	(segment
		(start 310.979312 -238.186976)
		(end 309.764938 -238.186976)
		(width 0.18288)
		(layer "In4.Cu")
		(net "M_C_CPU0_SB_DQS_DN<9>")
	)
	(segment
		(start 314.052204 -238.567468)
		(end 313.927744 -238.443008)
		(width 0.18288)
		(layer "In4.Cu")
		(net "M_C_CPU0_SB_DQS_DN<9>")
	)
	(segment
		(start 339.149182 -240.032032)
		(end 338.875624 -240.032032)
		(width 0.088646)
		(layer "In4.Cu")
		(net "M_C_CPU0_SB_DQS_DN<9>")
	)
	(segment
		(start 291.373814 -237.207806)
		(end 291.249354 -237.332266)
		(width 0.18288)
		(layer "In4.Cu")
		(net "M_C_CPU0_SB_DQS_DN<9>")
	)
	(segment
		(start 287.82391 -237.962694)
		(end 284.459426 -237.962694)
		(width 0.18288)
		(layer "In4.Cu")
		(net "M_C_CPU0_SB_DQS_DN<9>")
	)
	(segment
		(start 301.114968 -237.846616)
		(end 300.566328 -237.846616)
		(width 0.18288)
		(layer "In4.Cu")
		(net "M_C_CPU0_SB_DQS_DN<9>")
	)
	(segment
		(start 306.154582 -237.26902)
		(end 305.605942 -237.26902)
		(width 0.18288)
		(layer "In4.Cu")
		(net "M_C_CPU0_SB_DQS_DN<9>")
	)
	(segment
		(start 294.711882 -238.541814)
		(end 294.44696 -238.806736)
		(width 0.18288)
		(layer "In4.Cu")
		(net "M_C_CPU0_SB_DQS_DN<9>")
	)
	(segment
		(start 304.808382 -237.26902)
		(end 303.836324 -237.26902)
		(width 0.18288)
		(layer "In4.Cu")
		(net "M_C_CPU0_SB_DQS_DN<9>")
	)
	(segment
		(start 336.748374 -240.174272)
		(end 336.742532 -240.177828)
		(width 0.088646)
		(layer "In4.Cu")
		(net "M_C_CPU0_SB_DQS_DN<9>")
	)
	(segment
		(start 313.927744 -238.443008)
		(end 313.379104 -238.443008)
		(width 0.18288)
		(layer "In4.Cu")
		(net "M_C_CPU0_SB_DQS_DN<9>")
	)
	(segment
		(start 294.44696 -238.806736)
		(end 294.070024 -238.806736)
		(width 0.18288)
		(layer "In4.Cu")
		(net "M_C_CPU0_SB_DQS_DN<9>")
	)
	(segment
		(start 312.706004 -238.567468)
		(end 312.581544 -238.443008)
		(width 0.18288)
		(layer "In4.Cu")
		(net "M_C_CPU0_SB_DQS_DN<9>")
	)
	(segment
		(start 298.547028 -237.956598)
		(end 297.857672 -237.956598)
		(width 0.18288)
		(layer "In4.Cu")
		(net "M_C_CPU0_SB_DQS_DN<9>")
	)
	(segment
		(start 300.566328 -237.846616)
		(end 300.441868 -237.971076)
		(width 0.18288)
		(layer "In4.Cu")
		(net "M_C_CPU0_SB_DQS_DN<9>")
	)
	(segment
		(start 305.605942 -237.26902)
		(end 305.481482 -237.14456)
		(width 0.18288)
		(layer "In4.Cu")
		(net "M_C_CPU0_SB_DQS_DN<9>")
	)
	(segment
		(start 332.502002 -240.99901)
		(end 332.501494 -240.999264)
		(width 0.088646)
		(layer "In4.Cu")
		(net "M_C_CPU0_SB_DQS_DN<9>")
	)
	(segment
		(start 298.81195 -237.691676)
		(end 298.547028 -237.956598)
		(width 0.18288)
		(layer "In4.Cu")
		(net "M_C_CPU0_SB_DQS_DN<9>")
	)
	(segment
		(start 283.454348 -237.956598)
		(end 282.971494 -237.956598)
		(width 0.18288)
		(layer "In4.Cu")
		(net "M_C_CPU0_SB_DQS_DN<9>")
	)
	(segment
		(start 297.857672 -237.956598)
		(end 296.99839 -238.81588)
		(width 0.18288)
		(layer "In4.Cu")
		(net "M_C_CPU0_SB_DQS_DN<9>")
	)
	(segment
		(start 299.195744 -237.691676)
		(end 298.81195 -237.691676)
		(width 0.18288)
		(layer "In4.Cu")
		(net "M_C_CPU0_SB_DQS_DN<9>")
	)
	(segment
		(start 317.103252 -239.759998)
		(end 316.71514 -239.371886)
		(width 0.18288)
		(layer "In4.Cu")
		(net "M_C_CPU0_SB_DQS_DN<9>")
	)
	(segment
		(start 308.846982 -237.26902)
		(end 308.298342 -237.26902)
		(width 0.18288)
		(layer "In4.Cu")
		(net "M_C_CPU0_SB_DQS_DN<9>")
	)
	(segment
		(start 337.307682 -240.177574)
		(end 337.307682 -240.177828)
		(width 0.088646)
		(layer "In4.Cu")
		(net "M_C_CPU0_SB_DQS_DN<9>")
	)
	(segment
		(start 282.971494 -237.956598)
		(end 282.254706 -237.23981)
		(width 0.18288)
		(layer "In4.Cu")
		(net "M_C_CPU0_SB_DQS_DN<9>")
	)
	(segment
		(start 317.49111 -240.323878)
		(end 317.103252 -239.93602)
		(width 0.18288)
		(layer "In4.Cu")
		(net "M_C_CPU0_SB_DQS_DN<9>")
	)
	(segment
		(start 280.651458 -237.23981)
		(end 280.365962 -237.525306)
		(width 0.18288)
		(layer "In4.Cu")
		(net "M_C_CPU0_SB_DQS_DN<9>")
	)
	(segment
		(start 292.595554 -237.332266)
		(end 292.046914 -237.332266)
		(width 0.18288)
		(layer "In4.Cu")
		(net "M_C_CPU0_SB_DQS_DN<9>")
	)
	(segment
		(start 280.075386 -237.525306)
		(end 279.816814 -237.266734)
		(width 0.18288)
		(layer "In4.Cu")
		(net "M_C_CPU0_SB_DQS_DN<9>")
	)
	(segment
		(start 295.085516 -238.541814)
		(end 294.711882 -238.541814)
		(width 0.18288)
		(layer "In4.Cu")
		(net "M_C_CPU0_SB_DQS_DN<9>")
	)
	(segment
		(start 331.037692 -241.27587)
		(end 331.004164 -241.27587)
		(width 0.088646)
		(layer "In4.Cu")
		(net "M_C_CPU0_SB_DQS_DN<9>")
	)
	(segment
		(start 332.14183 -241.33556)
		(end 331.097382 -241.33556)
		(width 0.088646)
		(layer "In4.Cu")
		(net "M_C_CPU0_SB_DQS_DN<9>")
	)
	(segment
		(start 294.070024 -238.806736)
		(end 292.595554 -237.332266)
		(width 0.18288)
		(layer "In4.Cu")
		(net "M_C_CPU0_SB_DQS_DN<9>")
	)
	(segment
		(start 317.667132 -240.323878)
		(end 317.49111 -240.323878)
		(width 0.18288)
		(layer "In4.Cu")
		(net "M_C_CPU0_SB_DQS_DN<9>")
	)
	(segment
		(start 301.788068 -237.971076)
		(end 301.239428 -237.971076)
		(width 0.18288)
		(layer "In4.Cu")
		(net "M_C_CPU0_SB_DQS_DN<9>")
	)
	(segment
		(start 331.004164 -241.27587)
		(end 318.443102 -241.27587)
		(width 0.18288)
		(layer "In4.Cu")
		(net "M_C_CPU0_SB_DQS_DN<9>")
	)
	(segment
		(start 300.441868 -237.971076)
		(end 299.475144 -237.971076)
		(width 0.18288)
		(layer "In4.Cu")
		(net "M_C_CPU0_SB_DQS_DN<9>")
	)
	(segment
		(start 295.359582 -238.81588)
		(end 295.085516 -238.541814)
		(width 0.18288)
		(layer "In4.Cu")
		(net "M_C_CPU0_SB_DQS_DN<9>")
	)
	(segment
		(start 331.097382 -241.33556)
		(end 331.037692 -241.27587)
		(width 0.088646)
		(layer "In4.Cu")
		(net "M_C_CPU0_SB_DQS_DN<9>")
	)
	(segment
		(start 335.428082 -240.177574)
		(end 335.41335 -240.168938)
		(width 0.088646)
		(layer "In4.Cu")
		(net "M_C_CPU0_SB_DQS_DN<9>")
	)
	(segment
		(start 301.239428 -237.971076)
		(end 301.114968 -237.846616)
		(width 0.18288)
		(layer "In4.Cu")
		(net "M_C_CPU0_SB_DQS_DN<9>")
	)
	(segment
		(start 313.379104 -238.443008)
		(end 313.254644 -238.567468)
		(width 0.18288)
		(layer "In4.Cu")
		(net "M_C_CPU0_SB_DQS_DN<9>")
	)
	(segment
		(start 332.51394 -240.991898)
		(end 332.502764 -240.998502)
		(width 0.088646)
		(layer "In4.Cu")
		(net "M_C_CPU0_SB_DQS_DN<9>")
	)
	(segment
		(start 338.875624 -240.032032)
		(end 338.622386 -240.177828)
		(width 0.088646)
		(layer "In4.Cu")
		(net "M_C_CPU0_SB_DQS_DN<9>")
	)
	(segment
		(start 299.475144 -237.971076)
		(end 299.195744 -237.691676)
		(width 0.18288)
		(layer "In4.Cu")
		(net "M_C_CPU0_SB_DQS_DN<9>")
	)
	(segment
		(start 288.454338 -237.332266)
		(end 287.82391 -237.962694)
		(width 0.18288)
		(layer "In4.Cu")
		(net "M_C_CPU0_SB_DQS_DN<9>")
	)
	(segment
		(start 283.71927 -237.691676)
		(end 283.454348 -237.956598)
		(width 0.18288)
		(layer "In4.Cu")
		(net "M_C_CPU0_SB_DQS_DN<9>")
	)
	(segment
		(start 305.481482 -237.14456)
		(end 304.932842 -237.14456)
		(width 0.18288)
		(layer "In4.Cu")
		(net "M_C_CPU0_SB_DQS_DN<9>")
	)
	(segment
		(start 291.249354 -237.332266)
		(end 288.454338 -237.332266)
		(width 0.18288)
		(layer "In4.Cu")
		(net "M_C_CPU0_SB_DQS_DN<9>")
	)
	(segment
		(start 292.046914 -237.332266)
		(end 291.922454 -237.207806)
		(width 0.18288)
		(layer "In4.Cu")
		(net "M_C_CPU0_SB_DQS_DN<9>")
	)
	(segment
		(start 336.368136 -240.178082)
		(end 336.367882 -240.177574)
		(width 0.088646)
		(layer "In4.Cu")
		(net "M_C_CPU0_SB_DQS_DN<9>")
	)
	(segment
		(start 333.078836 -240.991644)
		(end 333.078328 -240.991898)
		(width 0.088646)
		(layer "In4.Cu")
		(net "M_C_CPU0_SB_DQS_DN<9>")
	)
	(segment
		(start 312.032904 -238.443008)
		(end 311.908444 -238.567468)
		(width 0.18288)
		(layer "In4.Cu")
		(net "M_C_CPU0_SB_DQS_DN<9>")
	)
	(segment
		(start 303.836324 -237.26902)
		(end 303.134268 -237.971076)
		(width 0.18288)
		(layer "In4.Cu")
		(net "M_C_CPU0_SB_DQS_DN<9>")
	)
	(segment
		(start 315.7347 -238.567468)
		(end 314.052204 -238.567468)
		(width 0.18288)
		(layer "In4.Cu")
		(net "M_C_CPU0_SB_DQS_DN<9>")
	)
	(segment
		(start 318.055244 -240.71199)
		(end 317.667132 -240.323878)
		(width 0.18288)
		(layer "In4.Cu")
		(net "M_C_CPU0_SB_DQS_DN<9>")
	)
	(segment
		(start 309.764938 -238.186976)
		(end 308.846982 -237.26902)
		(width 0.18288)
		(layer "In4.Cu")
		(net "M_C_CPU0_SB_DQS_DN<9>")
	)
	(segment
		(start 306.827682 -237.14456)
		(end 306.279042 -237.14456)
		(width 0.18288)
		(layer "In4.Cu")
		(net "M_C_CPU0_SB_DQS_DN<9>")
	)
	(segment
		(start 308.173882 -237.14456)
		(end 307.625242 -237.14456)
		(width 0.18288)
		(layer "In4.Cu")
		(net "M_C_CPU0_SB_DQS_DN<9>")
	)
	(segment
		(start 303.134268 -237.971076)
		(end 302.585628 -237.971076)
		(width 0.18288)
		(layer "In4.Cu")
		(net "M_C_CPU0_SB_DQS_DN<9>")
	)
	(segment
		(start 334.580484 -240.645188)
		(end 334.580484 -240.667286)
		(width 0.088646)
		(layer "In4.Cu")
		(net "M_C_CPU0_SB_DQS_DN<9>")
	)
	(segment
		(start 339.37448 -239.853216)
		(end 339.34273 -239.96904)
		(width 0.088646)
		(layer "In4.Cu")
		(net "M_C_CPU0_SB_DQS_DN<9>")
	)
	(segment
		(start 318.055244 -240.888012)
		(end 318.055244 -240.71199)
		(width 0.18288)
		(layer "In4.Cu")
		(net "M_C_CPU0_SB_DQS_DN<9>")
	)
	(segment
		(start 306.952142 -237.26902)
		(end 306.827682 -237.14456)
		(width 0.18288)
		(layer "In4.Cu")
		(net "M_C_CPU0_SB_DQS_DN<9>")
	)
	(segment
		(start 284.188408 -237.691676)
		(end 283.71927 -237.691676)
		(width 0.18288)
		(layer "In4.Cu")
		(net "M_C_CPU0_SB_DQS_DN<9>")
	)
	(segment
		(start 307.625242 -237.14456)
		(end 307.500782 -237.26902)
		(width 0.18288)
		(layer "In4.Cu")
		(net "M_C_CPU0_SB_DQS_DN<9>")
	)
	(segment
		(start 316.539118 -239.371886)
		(end 315.7347 -238.567468)
		(width 0.18288)
		(layer "In4.Cu")
		(net "M_C_CPU0_SB_DQS_DN<9>")
	)
	(segment
		(start 308.298342 -237.26902)
		(end 308.173882 -237.14456)
		(width 0.18288)
		(layer "In4.Cu")
		(net "M_C_CPU0_SB_DQS_DN<9>")
	)
	(segment
		(start 338.247736 -240.177574)
		(end 338.237322 -240.171478)
		(width 0.088646)
		(layer "In4.Cu")
		(net "M_C_CPU0_SB_DQS_DN<9>")
	)
	(segment
		(start 302.461168 -237.846616)
		(end 301.912528 -237.846616)
		(width 0.18288)
		(layer "In4.Cu")
		(net "M_C_CPU0_SB_DQS_DN<9>")
	)
	(segment
		(start 301.912528 -237.846616)
		(end 301.788068 -237.971076)
		(width 0.18288)
		(layer "In4.Cu")
		(net "M_C_CPU0_SB_DQS_DN<9>")
	)
	(segment
		(start 304.932842 -237.14456)
		(end 304.808382 -237.26902)
		(width 0.18288)
		(layer "In4.Cu")
		(net "M_C_CPU0_SB_DQS_DN<9>")
	)
	(segment
		(start 280.365962 -237.525306)
		(end 280.075386 -237.525306)
		(width 0.18288)
		(layer "In4.Cu")
		(net "M_C_CPU0_SB_DQS_DN<9>")
	)
	(segment
		(start 296.99839 -238.81588)
		(end 295.359582 -238.81588)
		(width 0.18288)
		(layer "In4.Cu")
		(net "M_C_CPU0_SB_DQS_DN<9>")
	)
	(segment
		(start 316.71514 -239.371886)
		(end 316.539118 -239.371886)
		(width 0.18288)
		(layer "In4.Cu")
		(net "M_C_CPU0_SB_DQS_DN<9>")
	)
	(segment
		(start 336.742532 -240.177828)
		(end 336.738722 -240.17986)
		(width 0.088646)
		(layer "In4.Cu")
		(net "M_C_CPU0_SB_DQS_DN<9>")
	)
	(segment
		(start 302.585628 -237.971076)
		(end 302.461168 -237.846616)
		(width 0.18288)
		(layer "In4.Cu")
		(net "M_C_CPU0_SB_DQS_DN<9>")
	)
	(segment
		(start 282.254706 -237.23981)
		(end 280.651458 -237.23981)
		(width 0.18288)
		(layer "In4.Cu")
		(net "M_C_CPU0_SB_DQS_DN<9>")
	)
	(segment
		(start 311.908444 -238.567468)
		(end 311.359804 -238.567468)
		(width 0.18288)
		(layer "In4.Cu")
		(net "M_C_CPU0_SB_DQS_DN<9>")
	)
	(segment
		(start 338.622386 -240.177828)
		(end 338.622132 -240.177574)
		(width 0.088646)
		(layer "In4.Cu")
		(net "M_C_CPU0_SB_DQS_DN<9>")
	)
	(arc
		(start 338.237322 -240.171478)
		(mid 337.95889 -240.101664)
		(end 337.682078 -240.177574)
		(width 0.088646)
		(layer "In4.Cu")
		(net "M_C_CPU0_SB_DQS_DN<9>")
	)
	(arc
		(start 333.078328 -240.991898)
		(mid 332.796134 -240.916342)
		(end 332.51394 -240.991898)
		(width 0.088646)
		(layer "In4.Cu")
		(net "M_C_CPU0_SB_DQS_DN<9>")
	)
	(arc
		(start 333.453232 -240.991644)
		(mid 333.266034 -241.041787)
		(end 333.078836 -240.991644)
		(width 0.088646)
		(layer "In4.Cu")
		(net "M_C_CPU0_SB_DQS_DN<9>")
	)
	(arc
		(start 335.41335 -240.168938)
		(mid 334.864854 -240.17618)
		(end 334.580484 -240.645188)
		(width 0.088646)
		(layer "In4.Cu")
		(net "M_C_CPU0_SB_DQS_DN<9>")
	)
	(arc
		(start 335.802478 -240.177574)
		(mid 335.61528 -240.227717)
		(end 335.428082 -240.177574)
		(width 0.088646)
		(layer "In4.Cu")
		(net "M_C_CPU0_SB_DQS_DN<9>")
	)
	(arc
		(start 336.35315 -240.168938)
		(mid 336.076709 -240.101772)
		(end 335.802478 -240.177574)
		(width 0.088646)
		(layer "In4.Cu")
		(net "M_C_CPU0_SB_DQS_DN<9>")
	)
	(arc
		(start 337.682078 -240.177574)
		(mid 337.49488 -240.227717)
		(end 337.307682 -240.177574)
		(width 0.088646)
		(layer "In4.Cu")
		(net "M_C_CPU0_SB_DQS_DN<9>")
	)
	(arc
		(start 339.303868 -239.991138)
		(mid 339.229183 -240.021643)
		(end 339.149182 -240.032032)
		(width 0.088646)
		(layer "In4.Cu")
		(net "M_C_CPU0_SB_DQS_DN<9>")
	)
	(arc
		(start 336.738722 -240.17986)
		(mid 336.553206 -240.227971)
		(end 336.368136 -240.178082)
		(width 0.088646)
		(layer "In4.Cu")
		(net "M_C_CPU0_SB_DQS_DN<9>")
	)
	(arc
		(start 334.018636 -240.991644)
		(mid 333.735934 -240.915868)
		(end 333.453232 -240.991644)
		(width 0.088646)
		(layer "In4.Cu")
		(net "M_C_CPU0_SB_DQS_DN<9>")
	)
	(arc
		(start 334.580484 -240.667286)
		(mid 334.393185 -240.991727)
		(end 334.018636 -240.991644)
		(width 0.088646)
		(layer "In4.Cu")
		(net "M_C_CPU0_SB_DQS_DN<9>")
	)
	(arc
		(start 337.307682 -240.177828)
		(mid 337.028508 -240.102063)
		(end 336.748374 -240.174272)
		(width 0.088646)
		(layer "In4.Cu")
		(net "M_C_CPU0_SB_DQS_DN<9>")
	)
	(arc
		(start 332.501494 -240.999264)
		(mid 332.44649 -241.03704)
		(end 332.396338 -241.081052)
		(width 0.088646)
		(layer "In4.Cu")
		(net "M_C_CPU0_SB_DQS_DN<9>")
	)
	(arc
		(start 338.622132 -240.177574)
		(mid 338.434934 -240.227717)
		(end 338.247736 -240.177574)
		(width 0.088646)
		(layer "In4.Cu")
		(net "M_C_CPU0_SB_DQS_DN<9>")
	)
	(segment
		(start 282.321508 -199.866758)
		(end 282.060396 -199.605646)
		(width 0.20066)
		(layer "F.Cu")
		(net "M_C_CPU0_SB_DQS_DN<8>")
	)
	(segment
		(start 277.595584 -199.441816)
		(end 277.58771 -199.44969)
		(width 0.101854)
		(layer "F.Cu")
		(net "M_C_CPU0_SB_DQS_DN<8>")
	)
	(segment
		(start 282.060396 -199.605646)
		(end 281.356816 -199.605646)
		(width 0.20066)
		(layer "F.Cu")
		(net "M_C_CPU0_SB_DQS_DN<8>")
	)
	(segment
		(start 276.474174 -199.605646)
		(end 276.000972 -199.605646)
		(width 0.20066)
		(layer "F.Cu")
		(net "M_C_CPU0_SB_DQS_DN<8>")
	)
	(segment
		(start 344.54338 -227.645214)
		(end 344.543634 -227.64496)
		(width 0.20066)
		(layer "F.Cu")
		(net "M_C_CPU0_SB_DQS_DN<8>")
	)
	(segment
		(start 277.58771 -199.44969)
		(end 277.402798 -199.44969)
		(width 0.20066)
		(layer "F.Cu")
		(net "M_C_CPU0_SB_DQS_DN<8>")
	)
	(segment
		(start 277.136352 -199.183244)
		(end 276.896576 -199.183244)
		(width 0.20066)
		(layer "F.Cu")
		(net "M_C_CPU0_SB_DQS_DN<8>")
	)
	(segment
		(start 281.356816 -199.605646)
		(end 280.7208 -199.180704)
		(width 0.20066)
		(layer "F.Cu")
		(net "M_C_CPU0_SB_DQS_DN<8>")
	)
	(segment
		(start 280.7208 -199.180704)
		(end 280.316178 -199.180704)
		(width 0.20066)
		(layer "F.Cu")
		(net "M_C_CPU0_SB_DQS_DN<8>")
	)
	(segment
		(start 277.402798 -199.44969)
		(end 277.136352 -199.183244)
		(width 0.20066)
		(layer "F.Cu")
		(net "M_C_CPU0_SB_DQS_DN<8>")
	)
	(segment
		(start 279.912826 -199.441816)
		(end 277.83536 -199.441816)
		(width 0.1016)
		(layer "F.Cu")
		(net "M_C_CPU0_SB_DQS_DN<8>")
	)
	(segment
		(start 282.811982 -199.866758)
		(end 282.321508 -199.866758)
		(width 0.20066)
		(layer "F.Cu")
		(net "M_C_CPU0_SB_DQS_DN<8>")
	)
	(segment
		(start 280.316178 -199.180704)
		(end 280.055066 -199.441816)
		(width 0.20066)
		(layer "F.Cu")
		(net "M_C_CPU0_SB_DQS_DN<8>")
	)
	(segment
		(start 275.73986 -199.866758)
		(end 275.268182 -199.866758)
		(width 0.20066)
		(layer "F.Cu")
		(net "M_C_CPU0_SB_DQS_DN<8>")
	)
	(segment
		(start 277.83536 -199.441816)
		(end 277.595584 -199.441816)
		(width 0.101854)
		(layer "F.Cu")
		(net "M_C_CPU0_SB_DQS_DN<8>")
	)
	(segment
		(start 283.916882 -199.866758)
		(end 282.811982 -199.866758)
		(width 0.20066)
		(layer "F.Cu")
		(net "M_C_CPU0_SB_DQS_DN<8>")
	)
	(segment
		(start 276.896576 -199.183244)
		(end 276.474174 -199.605646)
		(width 0.20066)
		(layer "F.Cu")
		(net "M_C_CPU0_SB_DQS_DN<8>")
	)
	(segment
		(start 276.000972 -199.605646)
		(end 275.73986 -199.866758)
		(width 0.20066)
		(layer "F.Cu")
		(net "M_C_CPU0_SB_DQS_DN<8>")
	)
	(segment
		(start 344.54338 -228.1809)
		(end 344.54338 -227.645214)
		(width 0.20066)
		(layer "F.Cu")
		(net "M_C_CPU0_SB_DQS_DN<8>")
	)
	(segment
		(start 280.055066 -199.441816)
		(end 279.912826 -199.441816)
		(width 0.20066)
		(layer "F.Cu")
		(net "M_C_CPU0_SB_DQS_DN<8>")
	)
	(segment
		(start 308.417976 -198.830692)
		(end 308.417976 -198.65467)
		(width 0.18288)
		(layer "In6.Cu")
		(net "M_C_CPU0_SB_DQS_DN<8>")
	)
	(segment
		(start 341.926164 -227.329238)
		(end 341.911432 -227.320602)
		(width 0.088646)
		(layer "In6.Cu")
		(net "M_C_CPU0_SB_DQS_DN<8>")
	)
	(segment
		(start 336.460084 -226.032822)
		(end 336.460084 -226.017328)
		(width 0.088646)
		(layer "In6.Cu")
		(net "M_C_CPU0_SB_DQS_DN<8>")
	)
	(segment
		(start 305.270154 -197.757542)
		(end 305.145694 -197.633082)
		(width 0.18288)
		(layer "In6.Cu")
		(net "M_C_CPU0_SB_DQS_DN<8>")
	)
	(segment
		(start 313.513216 -201.705464)
		(end 311.939178 -200.131426)
		(width 0.18288)
		(layer "In6.Cu")
		(net "M_C_CPU0_SB_DQS_DN<8>")
	)
	(segment
		(start 314.482988 -201.705464)
		(end 313.513216 -201.705464)
		(width 0.18288)
		(layer "In6.Cu")
		(net "M_C_CPU0_SB_DQS_DN<8>")
	)
	(segment
		(start 299.196506 -196.889116)
		(end 298.8056 -196.889116)
		(width 0.18288)
		(layer "In6.Cu")
		(net "M_C_CPU0_SB_DQS_DN<8>")
	)
	(segment
		(start 295.098216 -197.740778)
		(end 294.701722 -197.740778)
		(width 0.18288)
		(layer "In6.Cu")
		(net "M_C_CPU0_SB_DQS_DN<8>")
	)
	(segment
		(start 330.41971 -222.604838)
		(end 329.254358 -222.604838)
		(width 0.18288)
		(layer "In6.Cu")
		(net "M_C_CPU0_SB_DQS_DN<8>")
	)
	(segment
		(start 284.733492 -198.766176)
		(end 284.412182 -199.087486)
		(width 0.18288)
		(layer "In6.Cu")
		(net "M_C_CPU0_SB_DQS_DN<8>")
	)
	(segment
		(start 301.170594 -196.750178)
		(end 301.046134 -196.625718)
		(width 0.18288)
		(layer "In6.Cu")
		(net "M_C_CPU0_SB_DQS_DN<8>")
	)
	(segment
		(start 292.43782 -196.862446)
		(end 292.032182 -197.268084)
		(width 0.18288)
		(layer "In6.Cu")
		(net "M_C_CPU0_SB_DQS_DN<8>")
	)
	(segment
		(start 305.818794 -197.757542)
		(end 305.270154 -197.757542)
		(width 0.18288)
		(layer "In6.Cu")
		(net "M_C_CPU0_SB_DQS_DN<8>")
	)
	(segment
		(start 290.458398 -198.308722)
		(end 289.737038 -198.308722)
		(width 0.18288)
		(layer "In6.Cu")
		(net "M_C_CPU0_SB_DQS_DN<8>")
	)
	(segment
		(start 332.796388 -224.828354)
		(end 332.591918 -224.828354)
		(width 0.088646)
		(layer "In6.Cu")
		(net "M_C_CPU0_SB_DQS_DN<8>")
	)
	(segment
		(start 289.737038 -198.308722)
		(end 289.438334 -198.607426)
		(width 0.18288)
		(layer "In6.Cu")
		(net "M_C_CPU0_SB_DQS_DN<8>")
	)
	(segment
		(start 301.719234 -196.750178)
		(end 301.170594 -196.750178)
		(width 0.18288)
		(layer "In6.Cu")
		(net "M_C_CPU0_SB_DQS_DN<8>")
	)
	(segment
		(start 293.075614 -196.862446)
		(end 292.43782 -196.862446)
		(width 0.18288)
		(layer "In6.Cu")
		(net "M_C_CPU0_SB_DQS_DN<8>")
	)
	(segment
		(start 308.417976 -198.65467)
		(end 308.030118 -198.266812)
		(width 0.18288)
		(layer "In6.Cu")
		(net "M_C_CPU0_SB_DQS_DN<8>")
	)
	(segment
		(start 287.873186 -198.072502)
		(end 285.259018 -198.072502)
		(width 0.18288)
		(layer "In6.Cu")
		(net "M_C_CPU0_SB_DQS_DN<8>")
	)
	(segment
		(start 340.510622 -226.511866)
		(end 340.501732 -226.506786)
		(width 0.088646)
		(layer "In6.Cu")
		(net "M_C_CPU0_SB_DQS_DN<8>")
	)
	(segment
		(start 289.438334 -198.607426)
		(end 289.052 -198.607426)
		(width 0.18288)
		(layer "In6.Cu")
		(net "M_C_CPU0_SB_DQS_DN<8>")
	)
	(segment
		(start 330.502768 -222.545148)
		(end 330.443078 -222.604838)
		(width 0.088646)
		(layer "In6.Cu")
		(net "M_C_CPU0_SB_DQS_DN<8>")
	)
	(segment
		(start 315.844174 -203.242672)
		(end 315.456062 -202.85456)
		(width 0.18288)
		(layer "In6.Cu")
		(net "M_C_CPU0_SB_DQS_DN<8>")
	)
	(segment
		(start 340.986364 -227.329238)
		(end 340.971632 -227.320602)
		(width 0.088646)
		(layer "In6.Cu")
		(net "M_C_CPU0_SB_DQS_DN<8>")
	)
	(segment
		(start 306.983892 -197.633082)
		(end 305.943254 -197.633082)
		(width 0.18288)
		(layer "In6.Cu")
		(net "M_C_CPU0_SB_DQS_DN<8>")
	)
	(segment
		(start 295.36644 -197.472554)
		(end 295.098216 -197.740778)
		(width 0.18288)
		(layer "In6.Cu")
		(net "M_C_CPU0_SB_DQS_DN<8>")
	)
	(segment
		(start 342.865964 -227.329238)
		(end 342.851232 -227.320602)
		(width 0.088646)
		(layer "In6.Cu")
		(net "M_C_CPU0_SB_DQS_DN<8>")
	)
	(segment
		(start 292.032182 -197.268084)
		(end 291.121846 -197.645274)
		(width 0.18288)
		(layer "In6.Cu")
		(net "M_C_CPU0_SB_DQS_DN<8>")
	)
	(segment
		(start 315.456062 -202.85456)
		(end 315.456062 -202.678538)
		(width 0.18288)
		(layer "In6.Cu")
		(net "M_C_CPU0_SB_DQS_DN<8>")
	)
	(segment
		(start 331.380846 -223.617282)
		(end 331.380846 -222.80118)
		(width 0.088646)
		(layer "In6.Cu")
		(net "M_C_CPU0_SB_DQS_DN<8>")
	)
	(segment
		(start 328.687176 -222.037656)
		(end 328.687176 -219.76588)
		(width 0.18288)
		(layer "In6.Cu")
		(net "M_C_CPU0_SB_DQS_DN<8>")
	)
	(segment
		(start 301.046134 -196.625718)
		(end 299.459904 -196.625718)
		(width 0.18288)
		(layer "In6.Cu")
		(net "M_C_CPU0_SB_DQS_DN<8>")
	)
	(segment
		(start 335.811622 -224.88398)
		(end 335.802732 -224.8789)
		(width 0.088646)
		(layer "In6.Cu")
		(net "M_C_CPU0_SB_DQS_DN<8>")
	)
	(segment
		(start 288.774886 -198.330312)
		(end 288.130996 -198.330312)
		(width 0.18288)
		(layer "In6.Cu")
		(net "M_C_CPU0_SB_DQS_DN<8>")
	)
	(segment
		(start 298.375832 -196.638418)
		(end 296.361866 -197.472554)
		(width 0.18288)
		(layer "In6.Cu")
		(net "M_C_CPU0_SB_DQS_DN<8>")
	)
	(segment
		(start 284.733492 -198.598028)
		(end 284.733492 -198.766176)
		(width 0.18288)
		(layer "In6.Cu")
		(net "M_C_CPU0_SB_DQS_DN<8>")
	)
	(segment
		(start 336.281522 -225.69805)
		(end 336.272632 -225.69297)
		(width 0.088646)
		(layer "In6.Cu")
		(net "M_C_CPU0_SB_DQS_DN<8>")
	)
	(segment
		(start 293.688262 -197.475094)
		(end 293.075614 -196.862446)
		(width 0.18288)
		(layer "In6.Cu")
		(net "M_C_CPU0_SB_DQS_DN<8>")
	)
	(segment
		(start 310.645556 -200.131426)
		(end 309.363872 -199.600566)
		(width 0.18288)
		(layer "In6.Cu")
		(net "M_C_CPU0_SB_DQS_DN<8>")
	)
	(segment
		(start 337.307682 -226.506786)
		(end 337.29295 -226.515422)
		(width 0.088646)
		(layer "In6.Cu")
		(net "M_C_CPU0_SB_DQS_DN<8>")
	)
	(segment
		(start 298.554902 -196.638418)
		(end 298.375832 -196.638418)
		(width 0.18288)
		(layer "In6.Cu")
		(net "M_C_CPU0_SB_DQS_DN<8>")
	)
	(segment
		(start 329.254358 -222.604838)
		(end 328.687176 -222.037656)
		(width 0.18288)
		(layer "In6.Cu")
		(net "M_C_CPU0_SB_DQS_DN<8>")
	)
	(segment
		(start 331.124814 -222.545148)
		(end 330.502768 -222.545148)
		(width 0.088646)
		(layer "In6.Cu")
		(net "M_C_CPU0_SB_DQS_DN<8>")
	)
	(segment
		(start 316.408054 -203.63053)
		(end 316.020196 -203.242672)
		(width 0.18288)
		(layer "In6.Cu")
		(net "M_C_CPU0_SB_DQS_DN<8>")
	)
	(segment
		(start 338.632292 -226.512882)
		(end 338.621878 -226.506786)
		(width 0.088646)
		(layer "In6.Cu")
		(net "M_C_CPU0_SB_DQS_DN<8>")
	)
	(segment
		(start 305.145694 -197.633082)
		(end 303.555146 -197.633082)
		(width 0.18288)
		(layer "In6.Cu")
		(net "M_C_CPU0_SB_DQS_DN<8>")
	)
	(segment
		(start 305.943254 -197.633082)
		(end 305.818794 -197.757542)
		(width 0.18288)
		(layer "In6.Cu")
		(net "M_C_CPU0_SB_DQS_DN<8>")
	)
	(segment
		(start 294.701722 -197.740778)
		(end 294.436038 -197.475094)
		(width 0.18288)
		(layer "In6.Cu")
		(net "M_C_CPU0_SB_DQS_DN<8>")
	)
	(segment
		(start 320.046604 -211.125308)
		(end 317.360046 -204.582522)
		(width 0.18288)
		(layer "In6.Cu")
		(net "M_C_CPU0_SB_DQS_DN<8>")
	)
	(segment
		(start 298.8056 -196.889116)
		(end 298.554902 -196.638418)
		(width 0.18288)
		(layer "In6.Cu")
		(net "M_C_CPU0_SB_DQS_DN<8>")
	)
	(segment
		(start 289.052 -198.607426)
		(end 288.774886 -198.330312)
		(width 0.18288)
		(layer "In6.Cu")
		(net "M_C_CPU0_SB_DQS_DN<8>")
	)
	(segment
		(start 344.511884 -227.529136)
		(end 344.473022 -227.507038)
		(width 0.088646)
		(layer "In6.Cu")
		(net "M_C_CPU0_SB_DQS_DN<8>")
	)
	(segment
		(start 299.459904 -196.625718)
		(end 299.196506 -196.889116)
		(width 0.18288)
		(layer "In6.Cu")
		(net "M_C_CPU0_SB_DQS_DN<8>")
	)
	(segment
		(start 291.121846 -197.645274)
		(end 290.458398 -198.308722)
		(width 0.18288)
		(layer "In6.Cu")
		(net "M_C_CPU0_SB_DQS_DN<8>")
	)
	(segment
		(start 316.020196 -203.242672)
		(end 315.844174 -203.242672)
		(width 0.18288)
		(layer "In6.Cu")
		(net "M_C_CPU0_SB_DQS_DN<8>")
	)
	(segment
		(start 316.796166 -204.194664)
		(end 316.408054 -203.806552)
		(width 0.18288)
		(layer "In6.Cu")
		(net "M_C_CPU0_SB_DQS_DN<8>")
	)
	(segment
		(start 344.044778 -227.466144)
		(end 343.791032 -227.320602)
		(width 0.088646)
		(layer "In6.Cu")
		(net "M_C_CPU0_SB_DQS_DN<8>")
	)
	(segment
		(start 309.363872 -199.600566)
		(end 308.98211 -199.218804)
		(width 0.18288)
		(layer "In6.Cu")
		(net "M_C_CPU0_SB_DQS_DN<8>")
	)
	(segment
		(start 308.806088 -199.218804)
		(end 308.417976 -198.830692)
		(width 0.18288)
		(layer "In6.Cu")
		(net "M_C_CPU0_SB_DQS_DN<8>")
	)
	(segment
		(start 311.939178 -200.131426)
		(end 310.645556 -200.131426)
		(width 0.18288)
		(layer "In6.Cu")
		(net "M_C_CPU0_SB_DQS_DN<8>")
	)
	(segment
		(start 340.689184 -226.84105)
		(end 340.689184 -226.831144)
		(width 0.088646)
		(layer "In6.Cu")
		(net "M_C_CPU0_SB_DQS_DN<8>")
	)
	(segment
		(start 331.380846 -222.80118)
		(end 331.124814 -222.545148)
		(width 0.088646)
		(layer "In6.Cu")
		(net "M_C_CPU0_SB_DQS_DN<8>")
	)
	(segment
		(start 332.591918 -224.828354)
		(end 331.380846 -223.617282)
		(width 0.088646)
		(layer "In6.Cu")
		(net "M_C_CPU0_SB_DQS_DN<8>")
	)
	(segment
		(start 284.412182 -199.087486)
		(end 284.412182 -199.371458)
		(width 0.18288)
		(layer "In6.Cu")
		(net "M_C_CPU0_SB_DQS_DN<8>")
	)
	(segment
		(start 308.030118 -198.266812)
		(end 307.617622 -198.266812)
		(width 0.18288)
		(layer "In6.Cu")
		(net "M_C_CPU0_SB_DQS_DN<8>")
	)
	(segment
		(start 332.998064 -224.887536)
		(end 332.983332 -224.8789)
		(width 0.088646)
		(layer "In6.Cu")
		(net "M_C_CPU0_SB_DQS_DN<8>")
	)
	(segment
		(start 328.687176 -219.76588)
		(end 320.046604 -211.125308)
		(width 0.18288)
		(layer "In6.Cu")
		(net "M_C_CPU0_SB_DQS_DN<8>")
	)
	(segment
		(start 308.98211 -199.218804)
		(end 308.806088 -199.218804)
		(width 0.18288)
		(layer "In6.Cu")
		(net "M_C_CPU0_SB_DQS_DN<8>")
	)
	(segment
		(start 296.361866 -197.472554)
		(end 295.36644 -197.472554)
		(width 0.18288)
		(layer "In6.Cu")
		(net "M_C_CPU0_SB_DQS_DN<8>")
	)
	(segment
		(start 303.555146 -197.633082)
		(end 302.547782 -196.625718)
		(width 0.18288)
		(layer "In6.Cu")
		(net "M_C_CPU0_SB_DQS_DN<8>")
	)
	(segment
		(start 335.990184 -225.2218)
		(end 335.990184 -225.203258)
		(width 0.088646)
		(layer "In6.Cu")
		(net "M_C_CPU0_SB_DQS_DN<8>")
	)
	(segment
		(start 285.259018 -198.072502)
		(end 284.733492 -198.598028)
		(width 0.18288)
		(layer "In6.Cu")
		(net "M_C_CPU0_SB_DQS_DN<8>")
	)
	(segment
		(start 301.843694 -196.625718)
		(end 301.719234 -196.750178)
		(width 0.18288)
		(layer "In6.Cu")
		(net "M_C_CPU0_SB_DQS_DN<8>")
	)
	(segment
		(start 302.547782 -196.625718)
		(end 301.843694 -196.625718)
		(width 0.18288)
		(layer "In6.Cu")
		(net "M_C_CPU0_SB_DQS_DN<8>")
	)
	(segment
		(start 338.247482 -226.506786)
		(end 338.23275 -226.515422)
		(width 0.088646)
		(layer "In6.Cu")
		(net "M_C_CPU0_SB_DQS_DN<8>")
	)
	(segment
		(start 288.130996 -198.330312)
		(end 287.873186 -198.072502)
		(width 0.18288)
		(layer "In6.Cu")
		(net "M_C_CPU0_SB_DQS_DN<8>")
	)
	(segment
		(start 316.408054 -203.806552)
		(end 316.408054 -203.63053)
		(width 0.18288)
		(layer "In6.Cu")
		(net "M_C_CPU0_SB_DQS_DN<8>")
	)
	(segment
		(start 330.443078 -222.604838)
		(end 330.41971 -222.604838)
		(width 0.088646)
		(layer "In6.Cu")
		(net "M_C_CPU0_SB_DQS_DN<8>")
	)
	(segment
		(start 315.456062 -202.678538)
		(end 314.482988 -201.705464)
		(width 0.18288)
		(layer "In6.Cu")
		(net "M_C_CPU0_SB_DQS_DN<8>")
	)
	(segment
		(start 307.617622 -198.266812)
		(end 306.983892 -197.633082)
		(width 0.18288)
		(layer "In6.Cu")
		(net "M_C_CPU0_SB_DQS_DN<8>")
	)
	(segment
		(start 294.436038 -197.475094)
		(end 293.688262 -197.475094)
		(width 0.18288)
		(layer "In6.Cu")
		(net "M_C_CPU0_SB_DQS_DN<8>")
	)
	(segment
		(start 344.543634 -227.64496)
		(end 344.511884 -227.529136)
		(width 0.088646)
		(layer "In6.Cu")
		(net "M_C_CPU0_SB_DQS_DN<8>")
	)
	(segment
		(start 317.360046 -204.582522)
		(end 316.972188 -204.194664)
		(width 0.18288)
		(layer "In6.Cu")
		(net "M_C_CPU0_SB_DQS_DN<8>")
	)
	(segment
		(start 316.972188 -204.194664)
		(end 316.796166 -204.194664)
		(width 0.18288)
		(layer "In6.Cu")
		(net "M_C_CPU0_SB_DQS_DN<8>")
	)
	(segment
		(start 284.412182 -199.371458)
		(end 283.916882 -199.866758)
		(width 0.18288)
		(layer "In6.Cu")
		(net "M_C_CPU0_SB_DQS_DN<8>")
	)
	(segment
		(start 344.318336 -227.466144)
		(end 344.044778 -227.466144)
		(width 0.088646)
		(layer "In6.Cu")
		(net "M_C_CPU0_SB_DQS_DN<8>")
	)
	(arc
		(start 338.23275 -226.515422)
		(mid 337.956275 -226.582742)
		(end 337.682078 -226.506786)
		(width 0.088646)
		(layer "In6.Cu")
		(net "M_C_CPU0_SB_DQS_DN<8>")
	)
	(arc
		(start 335.802732 -224.8789)
		(mid 335.615534 -224.828757)
		(end 335.428336 -224.8789)
		(width 0.088646)
		(layer "In6.Cu")
		(net "M_C_CPU0_SB_DQS_DN<8>")
	)
	(arc
		(start 340.501732 -226.506786)
		(mid 340.314534 -226.456643)
		(end 340.127336 -226.506786)
		(width 0.088646)
		(layer "In6.Cu")
		(net "M_C_CPU0_SB_DQS_DN<8>")
	)
	(arc
		(start 335.990184 -225.203258)
		(mid 335.942505 -225.020358)
		(end 335.811622 -224.88398)
		(width 0.088646)
		(layer "In6.Cu")
		(net "M_C_CPU0_SB_DQS_DN<8>")
	)
	(arc
		(start 334.862932 -224.8789)
		(mid 334.675734 -224.828757)
		(end 334.488536 -224.8789)
		(width 0.088646)
		(layer "In6.Cu")
		(net "M_C_CPU0_SB_DQS_DN<8>")
	)
	(arc
		(start 343.416636 -227.320602)
		(mid 343.142437 -227.396437)
		(end 342.865964 -227.329238)
		(width 0.088646)
		(layer "In6.Cu")
		(net "M_C_CPU0_SB_DQS_DN<8>")
	)
	(arc
		(start 335.428336 -224.8789)
		(mid 335.145634 -224.954676)
		(end 334.862932 -224.8789)
		(width 0.088646)
		(layer "In6.Cu")
		(net "M_C_CPU0_SB_DQS_DN<8>")
	)
	(arc
		(start 336.272632 -225.69297)
		(mid 336.070346 -225.493989)
		(end 335.990184 -225.2218)
		(width 0.088646)
		(layer "In6.Cu")
		(net "M_C_CPU0_SB_DQS_DN<8>")
	)
	(arc
		(start 341.537036 -227.320602)
		(mid 341.262837 -227.396437)
		(end 340.986364 -227.329238)
		(width 0.088646)
		(layer "In6.Cu")
		(net "M_C_CPU0_SB_DQS_DN<8>")
	)
	(arc
		(start 334.488536 -224.8789)
		(mid 334.205834 -224.954676)
		(end 333.923132 -224.8789)
		(width 0.088646)
		(layer "In6.Cu")
		(net "M_C_CPU0_SB_DQS_DN<8>")
	)
	(arc
		(start 338.621878 -226.506786)
		(mid 338.43468 -226.456643)
		(end 338.247482 -226.506786)
		(width 0.088646)
		(layer "In6.Cu")
		(net "M_C_CPU0_SB_DQS_DN<8>")
	)
	(arc
		(start 340.689184 -226.831144)
		(mid 340.641505 -226.648244)
		(end 340.510622 -226.511866)
		(width 0.088646)
		(layer "In6.Cu")
		(net "M_C_CPU0_SB_DQS_DN<8>")
	)
	(arc
		(start 333.548736 -224.8789)
		(mid 333.274537 -224.954735)
		(end 332.998064 -224.887536)
		(width 0.088646)
		(layer "In6.Cu")
		(net "M_C_CPU0_SB_DQS_DN<8>")
	)
	(arc
		(start 342.476836 -227.320602)
		(mid 342.202637 -227.396437)
		(end 341.926164 -227.329238)
		(width 0.088646)
		(layer "In6.Cu")
		(net "M_C_CPU0_SB_DQS_DN<8>")
	)
	(arc
		(start 339.187536 -226.506786)
		(mid 338.910723 -226.582656)
		(end 338.632292 -226.512882)
		(width 0.088646)
		(layer "In6.Cu")
		(net "M_C_CPU0_SB_DQS_DN<8>")
	)
	(arc
		(start 342.851232 -227.320602)
		(mid 342.664034 -227.270459)
		(end 342.476836 -227.320602)
		(width 0.088646)
		(layer "In6.Cu")
		(net "M_C_CPU0_SB_DQS_DN<8>")
	)
	(arc
		(start 333.923132 -224.8789)
		(mid 333.735934 -224.828757)
		(end 333.548736 -224.8789)
		(width 0.088646)
		(layer "In6.Cu")
		(net "M_C_CPU0_SB_DQS_DN<8>")
	)
	(arc
		(start 332.82001 -224.829116)
		(mid 332.808205 -224.828549)
		(end 332.796388 -224.828354)
		(width 0.088646)
		(layer "In6.Cu")
		(net "M_C_CPU0_SB_DQS_DN<8>")
	)
	(arc
		(start 336.460084 -226.017328)
		(mid 336.412405 -225.834428)
		(end 336.281522 -225.69805)
		(width 0.088646)
		(layer "In6.Cu")
		(net "M_C_CPU0_SB_DQS_DN<8>")
	)
	(arc
		(start 341.911432 -227.320602)
		(mid 341.724234 -227.270459)
		(end 341.537036 -227.320602)
		(width 0.088646)
		(layer "In6.Cu")
		(net "M_C_CPU0_SB_DQS_DN<8>")
	)
	(arc
		(start 343.791032 -227.320602)
		(mid 343.603834 -227.270459)
		(end 343.416636 -227.320602)
		(width 0.088646)
		(layer "In6.Cu")
		(net "M_C_CPU0_SB_DQS_DN<8>")
	)
	(arc
		(start 336.742278 -226.506786)
		(mid 336.539455 -226.306555)
		(end 336.460084 -226.032822)
		(width 0.088646)
		(layer "In6.Cu")
		(net "M_C_CPU0_SB_DQS_DN<8>")
	)
	(arc
		(start 340.971632 -227.320602)
		(mid 340.767297 -227.117997)
		(end 340.689184 -226.84105)
		(width 0.088646)
		(layer "In6.Cu")
		(net "M_C_CPU0_SB_DQS_DN<8>")
	)
	(arc
		(start 344.473022 -227.507038)
		(mid 344.398337 -227.476533)
		(end 344.318336 -227.466144)
		(width 0.088646)
		(layer "In6.Cu")
		(net "M_C_CPU0_SB_DQS_DN<8>")
	)
	(arc
		(start 332.983332 -224.8789)
		(mid 332.904541 -224.844599)
		(end 332.82001 -224.829116)
		(width 0.088646)
		(layer "In6.Cu")
		(net "M_C_CPU0_SB_DQS_DN<8>")
	)
	(arc
		(start 339.561932 -226.506786)
		(mid 339.374734 -226.456643)
		(end 339.187536 -226.506786)
		(width 0.088646)
		(layer "In6.Cu")
		(net "M_C_CPU0_SB_DQS_DN<8>")
	)
	(arc
		(start 340.127336 -226.506786)
		(mid 339.844634 -226.582562)
		(end 339.561932 -226.506786)
		(width 0.088646)
		(layer "In6.Cu")
		(net "M_C_CPU0_SB_DQS_DN<8>")
	)
	(arc
		(start 337.682078 -226.506786)
		(mid 337.49488 -226.456643)
		(end 337.307682 -226.506786)
		(width 0.088646)
		(layer "In6.Cu")
		(net "M_C_CPU0_SB_DQS_DN<8>")
	)
	(arc
		(start 337.29295 -226.515422)
		(mid 337.016475 -226.582742)
		(end 336.742278 -226.506786)
		(width 0.088646)
		(layer "In6.Cu")
		(net "M_C_CPU0_SB_DQS_DN<8>")
	)
	(segment
		(start 280.7208 -208.530698)
		(end 280.316178 -208.530698)
		(width 0.20066)
		(layer "F.Cu")
		(net "M_C_CPU0_SB_DQS_DN<7>")
	)
	(segment
		(start 276.474174 -208.95564)
		(end 276.000972 -208.95564)
		(width 0.20066)
		(layer "F.Cu")
		(net "M_C_CPU0_SB_DQS_DN<7>")
	)
	(segment
		(start 280.316178 -208.530698)
		(end 280.055066 -208.79181)
		(width 0.20066)
		(layer "F.Cu")
		(net "M_C_CPU0_SB_DQS_DN<7>")
	)
	(segment
		(start 277.58771 -208.799684)
		(end 277.402798 -208.799684)
		(width 0.20066)
		(layer "F.Cu")
		(net "M_C_CPU0_SB_DQS_DN<7>")
	)
	(segment
		(start 280.055066 -208.79181)
		(end 279.912826 -208.79181)
		(width 0.20066)
		(layer "F.Cu")
		(net "M_C_CPU0_SB_DQS_DN<7>")
	)
	(segment
		(start 277.595584 -208.79181)
		(end 277.58771 -208.799684)
		(width 0.101854)
		(layer "F.Cu")
		(net "M_C_CPU0_SB_DQS_DN<7>")
	)
	(segment
		(start 277.136352 -208.533238)
		(end 276.896576 -208.533238)
		(width 0.20066)
		(layer "F.Cu")
		(net "M_C_CPU0_SB_DQS_DN<7>")
	)
	(segment
		(start 276.000972 -208.95564)
		(end 275.73986 -209.216752)
		(width 0.20066)
		(layer "F.Cu")
		(net "M_C_CPU0_SB_DQS_DN<7>")
	)
	(segment
		(start 275.73986 -209.216752)
		(end 275.268182 -209.216752)
		(width 0.20066)
		(layer "F.Cu")
		(net "M_C_CPU0_SB_DQS_DN<7>")
	)
	(segment
		(start 283.916882 -209.216752)
		(end 282.811982 -209.216752)
		(width 0.20066)
		(layer "F.Cu")
		(net "M_C_CPU0_SB_DQS_DN<7>")
	)
	(segment
		(start 279.912826 -208.79181)
		(end 277.83536 -208.79181)
		(width 0.1016)
		(layer "F.Cu")
		(net "M_C_CPU0_SB_DQS_DN<7>")
	)
	(segment
		(start 281.356816 -208.95564)
		(end 280.7208 -208.530698)
		(width 0.20066)
		(layer "F.Cu")
		(net "M_C_CPU0_SB_DQS_DN<7>")
	)
	(segment
		(start 282.811982 -209.216752)
		(end 282.321508 -209.216752)
		(width 0.20066)
		(layer "F.Cu")
		(net "M_C_CPU0_SB_DQS_DN<7>")
	)
	(segment
		(start 277.83536 -208.79181)
		(end 277.595584 -208.79181)
		(width 0.101854)
		(layer "F.Cu")
		(net "M_C_CPU0_SB_DQS_DN<7>")
	)
	(segment
		(start 282.321508 -209.216752)
		(end 282.060396 -208.95564)
		(width 0.20066)
		(layer "F.Cu")
		(net "M_C_CPU0_SB_DQS_DN<7>")
	)
	(segment
		(start 277.402798 -208.799684)
		(end 277.136352 -208.533238)
		(width 0.20066)
		(layer "F.Cu")
		(net "M_C_CPU0_SB_DQS_DN<7>")
	)
	(segment
		(start 282.060396 -208.95564)
		(end 281.356816 -208.95564)
		(width 0.20066)
		(layer "F.Cu")
		(net "M_C_CPU0_SB_DQS_DN<7>")
	)
	(segment
		(start 276.896576 -208.533238)
		(end 276.474174 -208.95564)
		(width 0.20066)
		(layer "F.Cu")
		(net "M_C_CPU0_SB_DQS_DN<7>")
	)
	(segment
		(start 341.254334 -230.622602)
		(end 341.254334 -230.086916)
		(width 0.20066)
		(layer "F.Cu")
		(net "M_C_CPU0_SB_DQS_DN<7>")
	)
	(segment
		(start 341.254334 -230.086916)
		(end 341.25408 -230.086662)
		(width 0.20066)
		(layer "F.Cu")
		(net "M_C_CPU0_SB_DQS_DN<7>")
	)
	(segment
		(start 284.600396 -208.938114)
		(end 284.19552 -208.938114)
		(width 0.18288)
		(layer "In4.Cu")
		(net "M_C_CPU0_SB_DQS_DN<7>")
	)
	(segment
		(start 299.460412 -210.2231)
		(end 299.19168 -210.491832)
		(width 0.18288)
		(layer "In4.Cu")
		(net "M_C_CPU0_SB_DQS_DN<7>")
	)
	(segment
		(start 293.646606 -211.043266)
		(end 292.209728 -209.606388)
		(width 0.18288)
		(layer "In4.Cu")
		(net "M_C_CPU0_SB_DQS_DN<7>")
	)
	(segment
		(start 331.011784 -228.603048)
		(end 330.731876 -228.603048)
		(width 0.088646)
		(layer "In4.Cu")
		(net "M_C_CPU0_SB_DQS_DN<7>")
	)
	(segment
		(start 341.567008 -230.086662)
		(end 341.624158 -230.029512)
		(width 0.088646)
		(layer "In4.Cu")
		(net "M_C_CPU0_SB_DQS_DN<7>")
	)
	(segment
		(start 310.312816 -210.072732)
		(end 309.870602 -209.630518)
		(width 0.18288)
		(layer "In4.Cu")
		(net "M_C_CPU0_SB_DQS_DN<7>")
	)
	(segment
		(start 299.19168 -210.491832)
		(end 298.81068 -210.491832)
		(width 0.18288)
		(layer "In4.Cu")
		(net "M_C_CPU0_SB_DQS_DN<7>")
	)
	(segment
		(start 338.622132 -229.762304)
		(end 338.61629 -229.758748)
		(width 0.088646)
		(layer "In4.Cu")
		(net "M_C_CPU0_SB_DQS_DN<7>")
	)
	(segment
		(start 334.488282 -229.762304)
		(end 334.47355 -229.77094)
		(width 0.088646)
		(layer "In4.Cu")
		(net "M_C_CPU0_SB_DQS_DN<7>")
	)
	(segment
		(start 315.192918 -212.058504)
		(end 314.159138 -211.024724)
		(width 0.18288)
		(layer "In4.Cu")
		(net "M_C_CPU0_SB_DQS_DN<7>")
	)
	(segment
		(start 333.548482 -229.762304)
		(end 333.53375 -229.77094)
		(width 0.088646)
		(layer "In4.Cu")
		(net "M_C_CPU0_SB_DQS_DN<7>")
	)
	(segment
		(start 336.744056 -229.763066)
		(end 336.742532 -229.762304)
		(width 0.088646)
		(layer "In4.Cu")
		(net "M_C_CPU0_SB_DQS_DN<7>")
	)
	(segment
		(start 335.428082 -229.762304)
		(end 335.41335 -229.77094)
		(width 0.088646)
		(layer "In4.Cu")
		(net "M_C_CPU0_SB_DQS_DN<7>")
	)
	(segment
		(start 332.608682 -229.762304)
		(end 332.608682 -229.76205)
		(width 0.088646)
		(layer "In4.Cu")
		(net "M_C_CPU0_SB_DQS_DN<7>")
	)
	(segment
		(start 298.542964 -210.224116)
		(end 297.927014 -210.224116)
		(width 0.18288)
		(layer "In4.Cu")
		(net "M_C_CPU0_SB_DQS_DN<7>")
	)
	(segment
		(start 338.627974 -229.765606)
		(end 338.622132 -229.762304)
		(width 0.088646)
		(layer "In4.Cu")
		(net "M_C_CPU0_SB_DQS_DN<7>")
	)
	(segment
		(start 314.159138 -211.024724)
		(end 313.610498 -211.024724)
		(width 0.18288)
		(layer "In4.Cu")
		(net "M_C_CPU0_SB_DQS_DN<7>")
	)
	(segment
		(start 330.731876 -228.603048)
		(end 330.671932 -228.662992)
		(width 0.088646)
		(layer "In4.Cu")
		(net "M_C_CPU0_SB_DQS_DN<7>")
	)
	(segment
		(start 331.126846 -228.71811)
		(end 331.011784 -228.603048)
		(width 0.088646)
		(layer "In4.Cu")
		(net "M_C_CPU0_SB_DQS_DN<7>")
	)
	(segment
		(start 330.648564 -228.662992)
		(end 325.85533 -228.662992)
		(width 0.18288)
		(layer "In4.Cu")
		(net "M_C_CPU0_SB_DQS_DN<7>")
	)
	(segment
		(start 294.41394 -211.043266)
		(end 293.646606 -211.043266)
		(width 0.18288)
		(layer "In4.Cu")
		(net "M_C_CPU0_SB_DQS_DN<7>")
	)
	(segment
		(start 290.230814 -209.606388)
		(end 289.843972 -209.219546)
		(width 0.18288)
		(layer "In4.Cu")
		(net "M_C_CPU0_SB_DQS_DN<7>")
	)
	(segment
		(start 341.066882 -229.762304)
		(end 341.05215 -229.77094)
		(width 0.088646)
		(layer "In4.Cu")
		(net "M_C_CPU0_SB_DQS_DN<7>")
	)
	(segment
		(start 319.398142 -222.205804)
		(end 315.192918 -212.058504)
		(width 0.18288)
		(layer "In4.Cu")
		(net "M_C_CPU0_SB_DQS_DN<7>")
	)
	(segment
		(start 292.209728 -209.606388)
		(end 290.230814 -209.606388)
		(width 0.18288)
		(layer "In4.Cu")
		(net "M_C_CPU0_SB_DQS_DN<7>")
	)
	(segment
		(start 313.610498 -211.024724)
		(end 313.486038 -211.149184)
		(width 0.18288)
		(layer "In4.Cu")
		(net "M_C_CPU0_SB_DQS_DN<7>")
	)
	(segment
		(start 336.742532 -229.762304)
		(end 336.738722 -229.760018)
		(width 0.088646)
		(layer "In4.Cu")
		(net "M_C_CPU0_SB_DQS_DN<7>")
	)
	(segment
		(start 332.08214 -229.837996)
		(end 331.126846 -228.882702)
		(width 0.088646)
		(layer "In4.Cu")
		(net "M_C_CPU0_SB_DQS_DN<7>")
	)
	(segment
		(start 310.87695 -210.636866)
		(end 310.700928 -210.636866)
		(width 0.18288)
		(layer "In4.Cu")
		(net "M_C_CPU0_SB_DQS_DN<7>")
	)
	(segment
		(start 325.85533 -228.662992)
		(end 319.398142 -222.205804)
		(width 0.18288)
		(layer "In4.Cu")
		(net "M_C_CPU0_SB_DQS_DN<7>")
	)
	(segment
		(start 337.688174 -229.765606)
		(end 337.682332 -229.762304)
		(width 0.088646)
		(layer "In4.Cu")
		(net "M_C_CPU0_SB_DQS_DN<7>")
	)
	(segment
		(start 297.927014 -210.224116)
		(end 297.054524 -211.096606)
		(width 0.18288)
		(layer "In4.Cu")
		(net "M_C_CPU0_SB_DQS_DN<7>")
	)
	(segment
		(start 336.748374 -229.765606)
		(end 336.744056 -229.763066)
		(width 0.088646)
		(layer "In4.Cu")
		(net "M_C_CPU0_SB_DQS_DN<7>")
	)
	(segment
		(start 297.054524 -211.096606)
		(end 295.33596 -211.096606)
		(width 0.18288)
		(layer "In4.Cu")
		(net "M_C_CPU0_SB_DQS_DN<7>")
	)
	(segment
		(start 313.486038 -211.149184)
		(end 312.937398 -211.149184)
		(width 0.18288)
		(layer "In4.Cu")
		(net "M_C_CPU0_SB_DQS_DN<7>")
	)
	(segment
		(start 284.881828 -209.219546)
		(end 284.600396 -208.938114)
		(width 0.18288)
		(layer "In4.Cu")
		(net "M_C_CPU0_SB_DQS_DN<7>")
	)
	(segment
		(start 295.33596 -211.096606)
		(end 295.090596 -211.34197)
		(width 0.18288)
		(layer "In4.Cu")
		(net "M_C_CPU0_SB_DQS_DN<7>")
	)
	(segment
		(start 309.870602 -209.630518)
		(end 303.77892 -209.630518)
		(width 0.18288)
		(layer "In4.Cu")
		(net "M_C_CPU0_SB_DQS_DN<7>")
	)
	(segment
		(start 337.682332 -229.762304)
		(end 337.67649 -229.758748)
		(width 0.088646)
		(layer "In4.Cu")
		(net "M_C_CPU0_SB_DQS_DN<7>")
	)
	(segment
		(start 303.77892 -209.630518)
		(end 303.186338 -210.2231)
		(width 0.18288)
		(layer "In4.Cu")
		(net "M_C_CPU0_SB_DQS_DN<7>")
	)
	(segment
		(start 341.25408 -230.086662)
		(end 341.567008 -230.086662)
		(width 0.088646)
		(layer "In4.Cu")
		(net "M_C_CPU0_SB_DQS_DN<7>")
	)
	(segment
		(start 332.326742 -229.837996)
		(end 332.08214 -229.837996)
		(width 0.088646)
		(layer "In4.Cu")
		(net "M_C_CPU0_SB_DQS_DN<7>")
	)
	(segment
		(start 310.700928 -210.636866)
		(end 310.312816 -210.248754)
		(width 0.18288)
		(layer "In4.Cu")
		(net "M_C_CPU0_SB_DQS_DN<7>")
	)
	(segment
		(start 339.561932 -229.762304)
		(end 339.55609 -229.758748)
		(width 0.088646)
		(layer "In4.Cu")
		(net "M_C_CPU0_SB_DQS_DN<7>")
	)
	(segment
		(start 294.712644 -211.34197)
		(end 294.41394 -211.043266)
		(width 0.18288)
		(layer "In4.Cu")
		(net "M_C_CPU0_SB_DQS_DN<7>")
	)
	(segment
		(start 331.126846 -228.882702)
		(end 331.126846 -228.71811)
		(width 0.088646)
		(layer "In4.Cu")
		(net "M_C_CPU0_SB_DQS_DN<7>")
	)
	(segment
		(start 330.671932 -228.662992)
		(end 330.648564 -228.662992)
		(width 0.088646)
		(layer "In4.Cu")
		(net "M_C_CPU0_SB_DQS_DN<7>")
	)
	(segment
		(start 284.19552 -208.938114)
		(end 283.916882 -209.216752)
		(width 0.18288)
		(layer "In4.Cu")
		(net "M_C_CPU0_SB_DQS_DN<7>")
	)
	(segment
		(start 295.090596 -211.34197)
		(end 294.712644 -211.34197)
		(width 0.18288)
		(layer "In4.Cu")
		(net "M_C_CPU0_SB_DQS_DN<7>")
	)
	(segment
		(start 312.812938 -211.024724)
		(end 311.264808 -211.024724)
		(width 0.18288)
		(layer "In4.Cu")
		(net "M_C_CPU0_SB_DQS_DN<7>")
	)
	(segment
		(start 303.186338 -210.2231)
		(end 299.460412 -210.2231)
		(width 0.18288)
		(layer "In4.Cu")
		(net "M_C_CPU0_SB_DQS_DN<7>")
	)
	(segment
		(start 298.81068 -210.491832)
		(end 298.542964 -210.224116)
		(width 0.18288)
		(layer "In4.Cu")
		(net "M_C_CPU0_SB_DQS_DN<7>")
	)
	(segment
		(start 311.264808 -211.024724)
		(end 310.87695 -210.636866)
		(width 0.18288)
		(layer "In4.Cu")
		(net "M_C_CPU0_SB_DQS_DN<7>")
	)
	(segment
		(start 310.312816 -210.248754)
		(end 310.312816 -210.072732)
		(width 0.18288)
		(layer "In4.Cu")
		(net "M_C_CPU0_SB_DQS_DN<7>")
	)
	(segment
		(start 339.567774 -229.765606)
		(end 339.561932 -229.762304)
		(width 0.088646)
		(layer "In4.Cu")
		(net "M_C_CPU0_SB_DQS_DN<7>")
	)
	(segment
		(start 312.937398 -211.149184)
		(end 312.812938 -211.024724)
		(width 0.18288)
		(layer "In4.Cu")
		(net "M_C_CPU0_SB_DQS_DN<7>")
	)
	(segment
		(start 336.367882 -229.762304)
		(end 336.35315 -229.77094)
		(width 0.088646)
		(layer "In4.Cu")
		(net "M_C_CPU0_SB_DQS_DN<7>")
	)
	(segment
		(start 289.843972 -209.219546)
		(end 284.881828 -209.219546)
		(width 0.18288)
		(layer "In4.Cu")
		(net "M_C_CPU0_SB_DQS_DN<7>")
	)
	(arc
		(start 338.61629 -229.758748)
		(mid 338.431405 -229.711955)
		(end 338.247482 -229.762304)
		(width 0.088646)
		(layer "In4.Cu")
		(net "M_C_CPU0_SB_DQS_DN<7>")
	)
	(arc
		(start 334.47355 -229.77094)
		(mid 334.197075 -229.83826)
		(end 333.922878 -229.762304)
		(width 0.088646)
		(layer "In4.Cu")
		(net "M_C_CPU0_SB_DQS_DN<7>")
	)
	(arc
		(start 340.127082 -229.762304)
		(mid 339.847879 -229.837944)
		(end 339.567774 -229.765606)
		(width 0.088646)
		(layer "In4.Cu")
		(net "M_C_CPU0_SB_DQS_DN<7>")
	)
	(arc
		(start 333.53375 -229.77094)
		(mid 333.257275 -229.83826)
		(end 332.983078 -229.762304)
		(width 0.088646)
		(layer "In4.Cu")
		(net "M_C_CPU0_SB_DQS_DN<7>")
	)
	(arc
		(start 336.35315 -229.77094)
		(mid 336.076675 -229.83826)
		(end 335.802478 -229.762304)
		(width 0.088646)
		(layer "In4.Cu")
		(net "M_C_CPU0_SB_DQS_DN<7>")
	)
	(arc
		(start 334.862678 -229.762304)
		(mid 334.67548 -229.712161)
		(end 334.488282 -229.762304)
		(width 0.088646)
		(layer "In4.Cu")
		(net "M_C_CPU0_SB_DQS_DN<7>")
	)
	(arc
		(start 335.41335 -229.77094)
		(mid 335.136875 -229.83826)
		(end 334.862678 -229.762304)
		(width 0.088646)
		(layer "In4.Cu")
		(net "M_C_CPU0_SB_DQS_DN<7>")
	)
	(arc
		(start 337.67649 -229.758748)
		(mid 337.491605 -229.711955)
		(end 337.307682 -229.762304)
		(width 0.088646)
		(layer "In4.Cu")
		(net "M_C_CPU0_SB_DQS_DN<7>")
	)
	(arc
		(start 341.05215 -229.77094)
		(mid 340.775675 -229.83826)
		(end 340.501478 -229.762304)
		(width 0.088646)
		(layer "In4.Cu")
		(net "M_C_CPU0_SB_DQS_DN<7>")
	)
	(arc
		(start 339.55609 -229.758748)
		(mid 339.371205 -229.711955)
		(end 339.187282 -229.762304)
		(width 0.088646)
		(layer "In4.Cu")
		(net "M_C_CPU0_SB_DQS_DN<7>")
	)
	(arc
		(start 336.738722 -229.760018)
		(mid 336.553003 -229.712066)
		(end 336.367882 -229.762304)
		(width 0.088646)
		(layer "In4.Cu")
		(net "M_C_CPU0_SB_DQS_DN<7>")
	)
	(arc
		(start 332.608682 -229.76205)
		(mid 332.472705 -229.818566)
		(end 332.326742 -229.837996)
		(width 0.088646)
		(layer "In4.Cu")
		(net "M_C_CPU0_SB_DQS_DN<7>")
	)
	(arc
		(start 337.307682 -229.762304)
		(mid 337.028479 -229.837944)
		(end 336.748374 -229.765606)
		(width 0.088646)
		(layer "In4.Cu")
		(net "M_C_CPU0_SB_DQS_DN<7>")
	)
	(arc
		(start 333.922878 -229.762304)
		(mid 333.73568 -229.712161)
		(end 333.548482 -229.762304)
		(width 0.088646)
		(layer "In4.Cu")
		(net "M_C_CPU0_SB_DQS_DN<7>")
	)
	(arc
		(start 340.501478 -229.762304)
		(mid 340.31428 -229.712161)
		(end 340.127082 -229.762304)
		(width 0.088646)
		(layer "In4.Cu")
		(net "M_C_CPU0_SB_DQS_DN<7>")
	)
	(arc
		(start 339.187282 -229.762304)
		(mid 338.908079 -229.837944)
		(end 338.627974 -229.765606)
		(width 0.088646)
		(layer "In4.Cu")
		(net "M_C_CPU0_SB_DQS_DN<7>")
	)
	(arc
		(start 338.247482 -229.762304)
		(mid 337.968279 -229.837944)
		(end 337.688174 -229.765606)
		(width 0.088646)
		(layer "In4.Cu")
		(net "M_C_CPU0_SB_DQS_DN<7>")
	)
	(arc
		(start 341.624158 -230.029512)
		(mid 341.415971 -229.749001)
		(end 341.066882 -229.762304)
		(width 0.088646)
		(layer "In4.Cu")
		(net "M_C_CPU0_SB_DQS_DN<7>")
	)
	(arc
		(start 332.983078 -229.762304)
		(mid 332.79588 -229.712161)
		(end 332.608682 -229.762304)
		(width 0.088646)
		(layer "In4.Cu")
		(net "M_C_CPU0_SB_DQS_DN<7>")
	)
	(arc
		(start 335.802478 -229.762304)
		(mid 335.61528 -229.712161)
		(end 335.428082 -229.762304)
		(width 0.088646)
		(layer "In4.Cu")
		(net "M_C_CPU0_SB_DQS_DN<7>")
	)
	(segment
		(start 283.916882 -218.566746)
		(end 282.811982 -218.566746)
		(width 0.20066)
		(layer "F.Cu")
		(net "M_C_CPU0_SB_DQS_DN<6>")
	)
	(segment
		(start 282.321508 -218.566746)
		(end 282.060396 -218.305634)
		(width 0.20066)
		(layer "F.Cu")
		(net "M_C_CPU0_SB_DQS_DN<6>")
	)
	(segment
		(start 281.356816 -218.305634)
		(end 280.7208 -217.880692)
		(width 0.20066)
		(layer "F.Cu")
		(net "M_C_CPU0_SB_DQS_DN<6>")
	)
	(segment
		(start 277.595584 -218.141804)
		(end 277.58771 -218.149678)
		(width 0.101854)
		(layer "F.Cu")
		(net "M_C_CPU0_SB_DQS_DN<6>")
	)
	(segment
		(start 344.54338 -237.947454)
		(end 344.543634 -237.9472)
		(width 0.20066)
		(layer "F.Cu")
		(net "M_C_CPU0_SB_DQS_DN<6>")
	)
	(segment
		(start 279.912826 -218.141804)
		(end 277.83536 -218.141804)
		(width 0.1016)
		(layer "F.Cu")
		(net "M_C_CPU0_SB_DQS_DN<6>")
	)
	(segment
		(start 277.83536 -218.141804)
		(end 277.595584 -218.141804)
		(width 0.101854)
		(layer "F.Cu")
		(net "M_C_CPU0_SB_DQS_DN<6>")
	)
	(segment
		(start 282.811982 -218.566746)
		(end 282.321508 -218.566746)
		(width 0.20066)
		(layer "F.Cu")
		(net "M_C_CPU0_SB_DQS_DN<6>")
	)
	(segment
		(start 344.543634 -237.9472)
		(end 344.543634 -237.411514)
		(width 0.20066)
		(layer "F.Cu")
		(net "M_C_CPU0_SB_DQS_DN<6>")
	)
	(segment
		(start 282.060396 -218.305634)
		(end 281.356816 -218.305634)
		(width 0.20066)
		(layer "F.Cu")
		(net "M_C_CPU0_SB_DQS_DN<6>")
	)
	(segment
		(start 280.316178 -217.880692)
		(end 280.055066 -218.141804)
		(width 0.20066)
		(layer "F.Cu")
		(net "M_C_CPU0_SB_DQS_DN<6>")
	)
	(segment
		(start 280.7208 -217.880692)
		(end 280.316178 -217.880692)
		(width 0.20066)
		(layer "F.Cu")
		(net "M_C_CPU0_SB_DQS_DN<6>")
	)
	(segment
		(start 275.73986 -218.566746)
		(end 275.268182 -218.566746)
		(width 0.20066)
		(layer "F.Cu")
		(net "M_C_CPU0_SB_DQS_DN<6>")
	)
	(segment
		(start 280.055066 -218.141804)
		(end 279.912826 -218.141804)
		(width 0.20066)
		(layer "F.Cu")
		(net "M_C_CPU0_SB_DQS_DN<6>")
	)
	(segment
		(start 276.474174 -218.305634)
		(end 276.000972 -218.305634)
		(width 0.20066)
		(layer "F.Cu")
		(net "M_C_CPU0_SB_DQS_DN<6>")
	)
	(segment
		(start 277.136352 -217.883232)
		(end 276.896576 -217.883232)
		(width 0.20066)
		(layer "F.Cu")
		(net "M_C_CPU0_SB_DQS_DN<6>")
	)
	(segment
		(start 276.896576 -217.883232)
		(end 276.474174 -218.305634)
		(width 0.20066)
		(layer "F.Cu")
		(net "M_C_CPU0_SB_DQS_DN<6>")
	)
	(segment
		(start 277.402798 -218.149678)
		(end 277.136352 -217.883232)
		(width 0.20066)
		(layer "F.Cu")
		(net "M_C_CPU0_SB_DQS_DN<6>")
	)
	(segment
		(start 276.000972 -218.305634)
		(end 275.73986 -218.566746)
		(width 0.20066)
		(layer "F.Cu")
		(net "M_C_CPU0_SB_DQS_DN<6>")
	)
	(segment
		(start 277.58771 -218.149678)
		(end 277.402798 -218.149678)
		(width 0.20066)
		(layer "F.Cu")
		(net "M_C_CPU0_SB_DQS_DN<6>")
	)
	(segment
		(start 309.045102 -221.64675)
		(end 308.496462 -221.64675)
		(width 0.18288)
		(layer "In6.Cu")
		(net "M_C_CPU0_SB_DQS_DN<6>")
	)
	(segment
		(start 338.166964 -237.096046)
		(end 338.152232 -237.08741)
		(width 0.088646)
		(layer "In6.Cu")
		(net "M_C_CPU0_SB_DQS_DN<6>")
	)
	(segment
		(start 289.554158 -218.95562)
		(end 288.619184 -218.95562)
		(width 0.18288)
		(layer "In6.Cu")
		(net "M_C_CPU0_SB_DQS_DN<6>")
	)
	(segment
		(start 330.975462 -234.642914)
		(end 330.858622 -234.642914)
		(width 0.088646)
		(layer "In6.Cu")
		(net "M_C_CPU0_SB_DQS_DN<6>")
	)
	(segment
		(start 294.382698 -220.40596)
		(end 293.71544 -220.40596)
		(width 0.18288)
		(layer "In6.Cu")
		(net "M_C_CPU0_SB_DQS_DN<6>")
	)
	(segment
		(start 330.858622 -234.642914)
		(end 330.798932 -234.702604)
		(width 0.088646)
		(layer "In6.Cu")
		(net "M_C_CPU0_SB_DQS_DN<6>")
	)
	(segment
		(start 330.775564 -234.702604)
		(end 322.724018 -234.702604)
		(width 0.18288)
		(layer "In6.Cu")
		(net "M_C_CPU0_SB_DQS_DN<6>")
	)
	(segment
		(start 330.798932 -234.702604)
		(end 330.775564 -234.702604)
		(width 0.088646)
		(layer "In6.Cu")
		(net "M_C_CPU0_SB_DQS_DN<6>")
	)
	(segment
		(start 299.536612 -221.25432)
		(end 299.248576 -221.542356)
		(width 0.18288)
		(layer "In6.Cu")
		(net "M_C_CPU0_SB_DQS_DN<6>")
	)
	(segment
		(start 314.310522 -224.942146)
		(end 313.89955 -224.942146)
		(width 0.18288)
		(layer "In6.Cu")
		(net "M_C_CPU0_SB_DQS_DN<6>")
	)
	(segment
		(start 331.790548 -236.018578)
		(end 331.790548 -235.656374)
		(width 0.088646)
		(layer "In6.Cu")
		(net "M_C_CPU0_SB_DQS_DN<6>")
	)
	(segment
		(start 307.56479 -221.52229)
		(end 306.600606 -220.558106)
		(width 0.18288)
		(layer "In6.Cu")
		(net "M_C_CPU0_SB_DQS_DN<6>")
	)
	(segment
		(start 303.02835 -221.25432)
		(end 299.536612 -221.25432)
		(width 0.18288)
		(layer "In6.Cu")
		(net "M_C_CPU0_SB_DQS_DN<6>")
	)
	(segment
		(start 337.227164 -237.096046)
		(end 337.212432 -237.08741)
		(width 0.088646)
		(layer "In6.Cu")
		(net "M_C_CPU0_SB_DQS_DN<6>")
	)
	(segment
		(start 298.492926 -221.248478)
		(end 297.904408 -221.248478)
		(width 0.18288)
		(layer "In6.Cu")
		(net "M_C_CPU0_SB_DQS_DN<6>")
	)
	(segment
		(start 305.159156 -220.558106)
		(end 303.724564 -220.558106)
		(width 0.18288)
		(layer "In6.Cu")
		(net "M_C_CPU0_SB_DQS_DN<6>")
	)
	(segment
		(start 344.543634 -237.411514)
		(end 344.856562 -237.411514)
		(width 0.088646)
		(layer "In6.Cu")
		(net "M_C_CPU0_SB_DQS_DN<6>")
	)
	(segment
		(start 308.496462 -221.64675)
		(end 308.372002 -221.52229)
		(width 0.18288)
		(layer "In6.Cu")
		(net "M_C_CPU0_SB_DQS_DN<6>")
	)
	(segment
		(start 297.904408 -221.248478)
		(end 297.067732 -220.411802)
		(width 0.18288)
		(layer "In6.Cu")
		(net "M_C_CPU0_SB_DQS_DN<6>")
	)
	(segment
		(start 284.174438 -218.30919)
		(end 283.916882 -218.566746)
		(width 0.18288)
		(layer "In6.Cu")
		(net "M_C_CPU0_SB_DQS_DN<6>")
	)
	(segment
		(start 339.102446 -237.093506)
		(end 339.092032 -237.08741)
		(width 0.088646)
		(layer "In6.Cu")
		(net "M_C_CPU0_SB_DQS_DN<6>")
	)
	(segment
		(start 314.546742 -224.705926)
		(end 314.310522 -224.942146)
		(width 0.18288)
		(layer "In6.Cu")
		(net "M_C_CPU0_SB_DQS_DN<6>")
	)
	(segment
		(start 316.150498 -228.129084)
		(end 316.150498 -225.959416)
		(width 0.18288)
		(layer "In6.Cu")
		(net "M_C_CPU0_SB_DQS_DN<6>")
	)
	(segment
		(start 284.715712 -218.539314)
		(end 284.485588 -218.30919)
		(width 0.18288)
		(layer "In6.Cu")
		(net "M_C_CPU0_SB_DQS_DN<6>")
	)
	(segment
		(start 305.283616 -220.682566)
		(end 305.159156 -220.558106)
		(width 0.18288)
		(layer "In6.Cu")
		(net "M_C_CPU0_SB_DQS_DN<6>")
	)
	(segment
		(start 306.600606 -220.558106)
		(end 305.956716 -220.558106)
		(width 0.18288)
		(layer "In6.Cu")
		(net "M_C_CPU0_SB_DQS_DN<6>")
	)
	(segment
		(start 342.865964 -237.096046)
		(end 342.851232 -237.08741)
		(width 0.088646)
		(layer "In6.Cu")
		(net "M_C_CPU0_SB_DQS_DN<6>")
	)
	(segment
		(start 334.110584 -236.607858)
		(end 334.110584 -236.597952)
		(width 0.088646)
		(layer "In6.Cu")
		(net "M_C_CPU0_SB_DQS_DN<6>")
	)
	(segment
		(start 291.8841 -220.32468)
		(end 290.923218 -220.32468)
		(width 0.18288)
		(layer "In6.Cu")
		(net "M_C_CPU0_SB_DQS_DN<6>")
	)
	(segment
		(start 340.041992 -237.093506)
		(end 340.031578 -237.08741)
		(width 0.088646)
		(layer "In6.Cu")
		(net "M_C_CPU0_SB_DQS_DN<6>")
	)
	(segment
		(start 299.248576 -221.542356)
		(end 298.786804 -221.542356)
		(width 0.18288)
		(layer "In6.Cu")
		(net "M_C_CPU0_SB_DQS_DN<6>")
	)
	(segment
		(start 313.643264 -224.68586)
		(end 312.710068 -224.68586)
		(width 0.18288)
		(layer "In6.Cu")
		(net "M_C_CPU0_SB_DQS_DN<6>")
	)
	(segment
		(start 314.895484 -224.705926)
		(end 314.546742 -224.705926)
		(width 0.18288)
		(layer "In6.Cu")
		(net "M_C_CPU0_SB_DQS_DN<6>")
	)
	(segment
		(start 332.32598 -236.34954)
		(end 332.12151 -236.34954)
		(width 0.088646)
		(layer "In6.Cu")
		(net "M_C_CPU0_SB_DQS_DN<6>")
	)
	(segment
		(start 313.89955 -224.942146)
		(end 313.643264 -224.68586)
		(width 0.18288)
		(layer "In6.Cu")
		(net "M_C_CPU0_SB_DQS_DN<6>")
	)
	(segment
		(start 322.724018 -234.702604)
		(end 316.150498 -228.129084)
		(width 0.18288)
		(layer "In6.Cu")
		(net "M_C_CPU0_SB_DQS_DN<6>")
	)
	(segment
		(start 310.025542 -221.52229)
		(end 309.169562 -221.52229)
		(width 0.18288)
		(layer "In6.Cu")
		(net "M_C_CPU0_SB_DQS_DN<6>")
	)
	(segment
		(start 308.372002 -221.52229)
		(end 307.56479 -221.52229)
		(width 0.18288)
		(layer "In6.Cu")
		(net "M_C_CPU0_SB_DQS_DN<6>")
	)
	(segment
		(start 331.079094 -234.746546)
		(end 330.975462 -234.642914)
		(width 0.088646)
		(layer "In6.Cu")
		(net "M_C_CPU0_SB_DQS_DN<6>")
	)
	(segment
		(start 295.426384 -220.411802)
		(end 295.146476 -220.69171)
		(width 0.18288)
		(layer "In6.Cu")
		(net "M_C_CPU0_SB_DQS_DN<6>")
	)
	(segment
		(start 332.12151 -236.34954)
		(end 331.790548 -236.018578)
		(width 0.088646)
		(layer "In6.Cu")
		(net "M_C_CPU0_SB_DQS_DN<6>")
	)
	(segment
		(start 334.958182 -237.08741)
		(end 334.947768 -237.093506)
		(width 0.088646)
		(layer "In6.Cu")
		(net "M_C_CPU0_SB_DQS_DN<6>")
	)
	(segment
		(start 331.079094 -234.94492)
		(end 331.079094 -234.746546)
		(width 0.088646)
		(layer "In6.Cu")
		(net "M_C_CPU0_SB_DQS_DN<6>")
	)
	(segment
		(start 303.724564 -220.558106)
		(end 303.02835 -221.25432)
		(width 0.18288)
		(layer "In6.Cu")
		(net "M_C_CPU0_SB_DQS_DN<6>")
	)
	(segment
		(start 294.668448 -220.69171)
		(end 294.382698 -220.40596)
		(width 0.18288)
		(layer "In6.Cu")
		(net "M_C_CPU0_SB_DQS_DN<6>")
	)
	(segment
		(start 343.805764 -237.096046)
		(end 343.791032 -237.08741)
		(width 0.088646)
		(layer "In6.Cu")
		(net "M_C_CPU0_SB_DQS_DN<6>")
	)
	(segment
		(start 298.786804 -221.542356)
		(end 298.492926 -221.248478)
		(width 0.18288)
		(layer "In6.Cu")
		(net "M_C_CPU0_SB_DQS_DN<6>")
	)
	(segment
		(start 312.710068 -224.68586)
		(end 311.250584 -223.22663)
		(width 0.18288)
		(layer "In6.Cu")
		(net "M_C_CPU0_SB_DQS_DN<6>")
	)
	(segment
		(start 310.651652 -221.781878)
		(end 310.025542 -221.52229)
		(width 0.18288)
		(layer "In6.Cu")
		(net "M_C_CPU0_SB_DQS_DN<6>")
	)
	(segment
		(start 344.856562 -237.411514)
		(end 344.913712 -237.354364)
		(width 0.088646)
		(layer "In6.Cu")
		(net "M_C_CPU0_SB_DQS_DN<6>")
	)
	(segment
		(start 316.150498 -225.959416)
		(end 314.895484 -224.705926)
		(width 0.18288)
		(layer "In6.Cu")
		(net "M_C_CPU0_SB_DQS_DN<6>")
	)
	(segment
		(start 293.023798 -219.714318)
		(end 292.494462 -219.714318)
		(width 0.18288)
		(layer "In6.Cu")
		(net "M_C_CPU0_SB_DQS_DN<6>")
	)
	(segment
		(start 293.71544 -220.40596)
		(end 293.023798 -219.714318)
		(width 0.18288)
		(layer "In6.Cu")
		(net "M_C_CPU0_SB_DQS_DN<6>")
	)
	(segment
		(start 287.615376 -218.539314)
		(end 284.715712 -218.539314)
		(width 0.18288)
		(layer "In6.Cu")
		(net "M_C_CPU0_SB_DQS_DN<6>")
	)
	(segment
		(start 333.548736 -236.273594)
		(end 333.534004 -236.28223)
		(width 0.088646)
		(layer "In6.Cu")
		(net "M_C_CPU0_SB_DQS_DN<6>")
	)
	(segment
		(start 290.923218 -220.32468)
		(end 289.554158 -218.95562)
		(width 0.18288)
		(layer "In6.Cu")
		(net "M_C_CPU0_SB_DQS_DN<6>")
	)
	(segment
		(start 331.790548 -235.656374)
		(end 331.079094 -234.94492)
		(width 0.088646)
		(layer "In6.Cu")
		(net "M_C_CPU0_SB_DQS_DN<6>")
	)
	(segment
		(start 305.832256 -220.682566)
		(end 305.283616 -220.682566)
		(width 0.18288)
		(layer "In6.Cu")
		(net "M_C_CPU0_SB_DQS_DN<6>")
	)
	(segment
		(start 295.146476 -220.69171)
		(end 294.668448 -220.69171)
		(width 0.18288)
		(layer "In6.Cu")
		(net "M_C_CPU0_SB_DQS_DN<6>")
	)
	(segment
		(start 335.898236 -237.08741)
		(end 335.887822 -237.093506)
		(width 0.088646)
		(layer "In6.Cu")
		(net "M_C_CPU0_SB_DQS_DN<6>")
	)
	(segment
		(start 311.250584 -223.22663)
		(end 310.651652 -221.781878)
		(width 0.18288)
		(layer "In6.Cu")
		(net "M_C_CPU0_SB_DQS_DN<6>")
	)
	(segment
		(start 288.619184 -218.95562)
		(end 287.615376 -218.539314)
		(width 0.18288)
		(layer "In6.Cu")
		(net "M_C_CPU0_SB_DQS_DN<6>")
	)
	(segment
		(start 305.956716 -220.558106)
		(end 305.832256 -220.682566)
		(width 0.18288)
		(layer "In6.Cu")
		(net "M_C_CPU0_SB_DQS_DN<6>")
	)
	(segment
		(start 340.986364 -237.096046)
		(end 340.971632 -237.08741)
		(width 0.088646)
		(layer "In6.Cu")
		(net "M_C_CPU0_SB_DQS_DN<6>")
	)
	(segment
		(start 309.169562 -221.52229)
		(end 309.045102 -221.64675)
		(width 0.18288)
		(layer "In6.Cu")
		(net "M_C_CPU0_SB_DQS_DN<6>")
	)
	(segment
		(start 284.485588 -218.30919)
		(end 284.174438 -218.30919)
		(width 0.18288)
		(layer "In6.Cu")
		(net "M_C_CPU0_SB_DQS_DN<6>")
	)
	(segment
		(start 292.494462 -219.714318)
		(end 291.8841 -220.32468)
		(width 0.18288)
		(layer "In6.Cu")
		(net "M_C_CPU0_SB_DQS_DN<6>")
	)
	(segment
		(start 297.067732 -220.411802)
		(end 295.426384 -220.411802)
		(width 0.18288)
		(layer "In6.Cu")
		(net "M_C_CPU0_SB_DQS_DN<6>")
	)
	(arc
		(start 343.791032 -237.08741)
		(mid 343.603834 -237.037233)
		(end 343.416636 -237.08741)
		(width 0.088646)
		(layer "In6.Cu")
		(net "M_C_CPU0_SB_DQS_DN<6>")
	)
	(arc
		(start 334.947768 -237.093506)
		(mid 334.392091 -237.086954)
		(end 334.110584 -236.607858)
		(width 0.088646)
		(layer "In6.Cu")
		(net "M_C_CPU0_SB_DQS_DN<6>")
	)
	(arc
		(start 340.031578 -237.08741)
		(mid 339.84438 -237.037233)
		(end 339.657182 -237.08741)
		(width 0.088646)
		(layer "In6.Cu")
		(net "M_C_CPU0_SB_DQS_DN<6>")
	)
	(arc
		(start 344.356436 -237.08741)
		(mid 344.082237 -237.163245)
		(end 343.805764 -237.096046)
		(width 0.088646)
		(layer "In6.Cu")
		(net "M_C_CPU0_SB_DQS_DN<6>")
	)
	(arc
		(start 340.971632 -237.08741)
		(mid 340.784434 -237.037233)
		(end 340.597236 -237.08741)
		(width 0.088646)
		(layer "In6.Cu")
		(net "M_C_CPU0_SB_DQS_DN<6>")
	)
	(arc
		(start 339.657182 -237.08741)
		(mid 339.380623 -237.163153)
		(end 339.102446 -237.093506)
		(width 0.088646)
		(layer "In6.Cu")
		(net "M_C_CPU0_SB_DQS_DN<6>")
	)
	(arc
		(start 342.851232 -237.08741)
		(mid 342.664034 -237.037233)
		(end 342.476836 -237.08741)
		(width 0.088646)
		(layer "In6.Cu")
		(net "M_C_CPU0_SB_DQS_DN<6>")
	)
	(arc
		(start 343.416636 -237.08741)
		(mid 343.142437 -237.163245)
		(end 342.865964 -237.096046)
		(width 0.088646)
		(layer "In6.Cu")
		(net "M_C_CPU0_SB_DQS_DN<6>")
	)
	(arc
		(start 340.597236 -237.08741)
		(mid 340.320423 -237.16328)
		(end 340.041992 -237.093506)
		(width 0.088646)
		(layer "In6.Cu")
		(net "M_C_CPU0_SB_DQS_DN<6>")
	)
	(arc
		(start 337.212432 -237.08741)
		(mid 337.025234 -237.037233)
		(end 336.838036 -237.08741)
		(width 0.088646)
		(layer "In6.Cu")
		(net "M_C_CPU0_SB_DQS_DN<6>")
	)
	(arc
		(start 344.913712 -237.354364)
		(mid 344.705468 -237.073825)
		(end 344.356436 -237.08741)
		(width 0.088646)
		(layer "In6.Cu")
		(net "M_C_CPU0_SB_DQS_DN<6>")
	)
	(arc
		(start 335.332578 -237.08741)
		(mid 335.14538 -237.037267)
		(end 334.958182 -237.08741)
		(width 0.088646)
		(layer "In6.Cu")
		(net "M_C_CPU0_SB_DQS_DN<6>")
	)
	(arc
		(start 336.838036 -237.08741)
		(mid 336.555334 -237.163186)
		(end 336.272632 -237.08741)
		(width 0.088646)
		(layer "In6.Cu")
		(net "M_C_CPU0_SB_DQS_DN<6>")
	)
	(arc
		(start 333.534004 -236.28223)
		(mid 333.257529 -236.34955)
		(end 332.983332 -236.273594)
		(width 0.088646)
		(layer "In6.Cu")
		(net "M_C_CPU0_SB_DQS_DN<6>")
	)
	(arc
		(start 332.608936 -236.273594)
		(mid 332.472464 -236.330217)
		(end 332.32598 -236.34954)
		(width 0.088646)
		(layer "In6.Cu")
		(net "M_C_CPU0_SB_DQS_DN<6>")
	)
	(arc
		(start 335.887822 -237.093506)
		(mid 335.60939 -237.163352)
		(end 335.332578 -237.08741)
		(width 0.088646)
		(layer "In6.Cu")
		(net "M_C_CPU0_SB_DQS_DN<6>")
	)
	(arc
		(start 338.152232 -237.08741)
		(mid 337.965034 -237.037233)
		(end 337.777836 -237.08741)
		(width 0.088646)
		(layer "In6.Cu")
		(net "M_C_CPU0_SB_DQS_DN<6>")
	)
	(arc
		(start 332.983332 -236.273594)
		(mid 332.796134 -236.223451)
		(end 332.608936 -236.273594)
		(width 0.088646)
		(layer "In6.Cu")
		(net "M_C_CPU0_SB_DQS_DN<6>")
	)
	(arc
		(start 337.777836 -237.08741)
		(mid 337.503637 -237.163245)
		(end 337.227164 -237.096046)
		(width 0.088646)
		(layer "In6.Cu")
		(net "M_C_CPU0_SB_DQS_DN<6>")
	)
	(arc
		(start 341.911432 -237.08741)
		(mid 341.724234 -237.037233)
		(end 341.537036 -237.08741)
		(width 0.088646)
		(layer "In6.Cu")
		(net "M_C_CPU0_SB_DQS_DN<6>")
	)
	(arc
		(start 339.092032 -237.08741)
		(mid 338.904834 -237.037233)
		(end 338.717636 -237.08741)
		(width 0.088646)
		(layer "In6.Cu")
		(net "M_C_CPU0_SB_DQS_DN<6>")
	)
	(arc
		(start 341.537036 -237.08741)
		(mid 341.262837 -237.163245)
		(end 340.986364 -237.096046)
		(width 0.088646)
		(layer "In6.Cu")
		(net "M_C_CPU0_SB_DQS_DN<6>")
	)
	(arc
		(start 342.476836 -237.08741)
		(mid 342.194134 -237.163186)
		(end 341.911432 -237.08741)
		(width 0.088646)
		(layer "In6.Cu")
		(net "M_C_CPU0_SB_DQS_DN<6>")
	)
	(arc
		(start 334.110584 -236.597952)
		(mid 333.923285 -236.273511)
		(end 333.548736 -236.273594)
		(width 0.088646)
		(layer "In6.Cu")
		(net "M_C_CPU0_SB_DQS_DN<6>")
	)
	(arc
		(start 338.717636 -237.08741)
		(mid 338.443437 -237.163245)
		(end 338.166964 -237.096046)
		(width 0.088646)
		(layer "In6.Cu")
		(net "M_C_CPU0_SB_DQS_DN<6>")
	)
	(arc
		(start 336.272632 -237.08741)
		(mid 336.085434 -237.037233)
		(end 335.898236 -237.08741)
		(width 0.088646)
		(layer "In6.Cu")
		(net "M_C_CPU0_SB_DQS_DN<6>")
	)
	(segment
		(start 276.000972 -227.655628)
		(end 275.73986 -227.91674)
		(width 0.20066)
		(layer "F.Cu")
		(net "M_C_CPU0_SB_DQS_DN<5>")
	)
	(segment
		(start 277.595584 -227.491798)
		(end 277.58771 -227.499672)
		(width 0.101854)
		(layer "F.Cu")
		(net "M_C_CPU0_SB_DQS_DN<5>")
	)
	(segment
		(start 280.7208 -227.230686)
		(end 280.316178 -227.230686)
		(width 0.20066)
		(layer "F.Cu")
		(net "M_C_CPU0_SB_DQS_DN<5>")
	)
	(segment
		(start 277.58771 -227.499672)
		(end 277.402798 -227.499672)
		(width 0.20066)
		(layer "F.Cu")
		(net "M_C_CPU0_SB_DQS_DN<5>")
	)
	(segment
		(start 276.896576 -227.233226)
		(end 276.474174 -227.655628)
		(width 0.20066)
		(layer "F.Cu")
		(net "M_C_CPU0_SB_DQS_DN<5>")
	)
	(segment
		(start 282.321508 -227.91674)
		(end 282.060396 -227.655628)
		(width 0.20066)
		(layer "F.Cu")
		(net "M_C_CPU0_SB_DQS_DN<5>")
	)
	(segment
		(start 279.912826 -227.491798)
		(end 277.83536 -227.491798)
		(width 0.1016)
		(layer "F.Cu")
		(net "M_C_CPU0_SB_DQS_DN<5>")
	)
	(segment
		(start 344.54338 -242.830858)
		(end 344.543634 -242.294918)
		(width 0.20066)
		(layer "F.Cu")
		(net "M_C_CPU0_SB_DQS_DN<5>")
	)
	(segment
		(start 282.060396 -227.655628)
		(end 281.356816 -227.655628)
		(width 0.20066)
		(layer "F.Cu")
		(net "M_C_CPU0_SB_DQS_DN<5>")
	)
	(segment
		(start 280.055066 -227.491798)
		(end 279.912826 -227.491798)
		(width 0.20066)
		(layer "F.Cu")
		(net "M_C_CPU0_SB_DQS_DN<5>")
	)
	(segment
		(start 275.73986 -227.91674)
		(end 275.268182 -227.91674)
		(width 0.20066)
		(layer "F.Cu")
		(net "M_C_CPU0_SB_DQS_DN<5>")
	)
	(segment
		(start 277.136352 -227.233226)
		(end 276.896576 -227.233226)
		(width 0.20066)
		(layer "F.Cu")
		(net "M_C_CPU0_SB_DQS_DN<5>")
	)
	(segment
		(start 282.811982 -227.91674)
		(end 282.321508 -227.91674)
		(width 0.20066)
		(layer "F.Cu")
		(net "M_C_CPU0_SB_DQS_DN<5>")
	)
	(segment
		(start 277.402798 -227.499672)
		(end 277.136352 -227.233226)
		(width 0.20066)
		(layer "F.Cu")
		(net "M_C_CPU0_SB_DQS_DN<5>")
	)
	(segment
		(start 280.316178 -227.230686)
		(end 280.055066 -227.491798)
		(width 0.20066)
		(layer "F.Cu")
		(net "M_C_CPU0_SB_DQS_DN<5>")
	)
	(segment
		(start 283.916882 -227.91674)
		(end 282.811982 -227.91674)
		(width 0.20066)
		(layer "F.Cu")
		(net "M_C_CPU0_SB_DQS_DN<5>")
	)
	(segment
		(start 276.474174 -227.655628)
		(end 276.000972 -227.655628)
		(width 0.20066)
		(layer "F.Cu")
		(net "M_C_CPU0_SB_DQS_DN<5>")
	)
	(segment
		(start 281.356816 -227.655628)
		(end 280.7208 -227.230686)
		(width 0.20066)
		(layer "F.Cu")
		(net "M_C_CPU0_SB_DQS_DN<5>")
	)
	(segment
		(start 277.83536 -227.491798)
		(end 277.595584 -227.491798)
		(width 0.101854)
		(layer "F.Cu")
		(net "M_C_CPU0_SB_DQS_DN<5>")
	)
	(segment
		(start 315.315092 -236.331506)
		(end 313.649614 -236.331506)
		(width 0.18288)
		(layer "In6.Cu")
		(net "M_C_CPU0_SB_DQS_DN<5>")
	)
	(segment
		(start 344.356436 -241.97056)
		(end 344.356182 -241.97056)
		(width 0.088646)
		(layer "In6.Cu")
		(net "M_C_CPU0_SB_DQS_DN<5>")
	)
	(segment
		(start 305.05781 -233.32694)
		(end 304.93335 -233.20248)
		(width 0.18288)
		(layer "In6.Cu")
		(net "M_C_CPU0_SB_DQS_DN<5>")
	)
	(segment
		(start 298.520866 -232.306114)
		(end 297.875198 -232.306114)
		(width 0.18288)
		(layer "In6.Cu")
		(net "M_C_CPU0_SB_DQS_DN<5>")
	)
	(segment
		(start 332.089506 -241.304572)
		(end 331.343508 -240.558574)
		(width 0.088646)
		(layer "In6.Cu")
		(net "M_C_CPU0_SB_DQS_DN<5>")
	)
	(segment
		(start 344.356182 -241.97056)
		(end 344.355928 -241.970306)
		(width 0.088646)
		(layer "In6.Cu")
		(net "M_C_CPU0_SB_DQS_DN<5>")
	)
	(segment
		(start 331.112622 -240.558574)
		(end 331.052932 -240.618264)
		(width 0.088646)
		(layer "In6.Cu")
		(net "M_C_CPU0_SB_DQS_DN<5>")
	)
	(segment
		(start 287.976564 -228.97846)
		(end 286.92348 -228.97846)
		(width 0.18288)
		(layer "In6.Cu")
		(net "M_C_CPU0_SB_DQS_DN<5>")
	)
	(segment
		(start 292.999414 -230.690166)
		(end 292.435534 -230.690166)
		(width 0.18288)
		(layer "In6.Cu")
		(net "M_C_CPU0_SB_DQS_DN<5>")
	)
	(segment
		(start 338.151724 -241.970052)
		(end 338.139786 -241.96294)
		(width 0.088646)
		(layer "In6.Cu")
		(net "M_C_CPU0_SB_DQS_DN<5>")
	)
	(segment
		(start 344.73642 -241.973608)
		(end 344.730832 -241.97056)
		(width 0.088646)
		(layer "In6.Cu")
		(net "M_C_CPU0_SB_DQS_DN<5>")
	)
	(segment
		(start 312.410094 -235.091986)
		(end 311.809638 -235.091986)
		(width 0.18288)
		(layer "In6.Cu")
		(net "M_C_CPU0_SB_DQS_DN<5>")
	)
	(segment
		(start 291.754814 -230.009446)
		(end 289.00755 -230.009446)
		(width 0.18288)
		(layer "In6.Cu")
		(net "M_C_CPU0_SB_DQS_DN<5>")
	)
	(segment
		(start 310.665876 -233.948224)
		(end 309.186834 -233.948224)
		(width 0.18288)
		(layer "In6.Cu")
		(net "M_C_CPU0_SB_DQS_DN<5>")
	)
	(segment
		(start 292.435534 -230.690166)
		(end 291.754814 -230.009446)
		(width 0.18288)
		(layer "In6.Cu")
		(net "M_C_CPU0_SB_DQS_DN<5>")
	)
	(segment
		(start 339.091524 -241.970052)
		(end 339.079586 -241.96294)
		(width 0.088646)
		(layer "In6.Cu")
		(net "M_C_CPU0_SB_DQS_DN<5>")
	)
	(segment
		(start 309.186834 -233.948224)
		(end 309.062374 -234.072684)
		(width 0.18288)
		(layer "In6.Cu")
		(net "M_C_CPU0_SB_DQS_DN<5>")
	)
	(segment
		(start 295.96842 -231.462072)
		(end 295.464484 -231.462072)
		(width 0.18288)
		(layer "In6.Cu")
		(net "M_C_CPU0_SB_DQS_DN<5>")
	)
	(segment
		(start 289.00755 -230.009446)
		(end 287.976564 -228.97846)
		(width 0.18288)
		(layer "In6.Cu")
		(net "M_C_CPU0_SB_DQS_DN<5>")
	)
	(segment
		(start 295.18483 -231.741726)
		(end 294.706294 -231.741726)
		(width 0.18288)
		(layer "In6.Cu")
		(net "M_C_CPU0_SB_DQS_DN<5>")
	)
	(segment
		(start 340.971124 -241.970052)
		(end 340.959186 -241.96294)
		(width 0.088646)
		(layer "In6.Cu")
		(net "M_C_CPU0_SB_DQS_DN<5>")
	)
	(segment
		(start 284.535372 -227.657914)
		(end 284.175708 -227.657914)
		(width 0.18288)
		(layer "In6.Cu")
		(net "M_C_CPU0_SB_DQS_DN<5>")
	)
	(segment
		(start 284.175708 -227.657914)
		(end 283.916882 -227.91674)
		(width 0.18288)
		(layer "In6.Cu")
		(net "M_C_CPU0_SB_DQS_DN<5>")
	)
	(segment
		(start 331.052932 -240.618264)
		(end 331.029564 -240.618264)
		(width 0.088646)
		(layer "In6.Cu")
		(net "M_C_CPU0_SB_DQS_DN<5>")
	)
	(segment
		(start 336.282792 -241.976148)
		(end 336.260694 -241.963194)
		(width 0.088646)
		(layer "In6.Cu")
		(net "M_C_CPU0_SB_DQS_DN<5>")
	)
	(segment
		(start 342.850724 -241.970052)
		(end 342.842342 -241.965226)
		(width 0.088646)
		(layer "In6.Cu")
		(net "M_C_CPU0_SB_DQS_DN<5>")
	)
	(segment
		(start 284.694884 -227.817426)
		(end 284.535372 -227.657914)
		(width 0.18288)
		(layer "In6.Cu")
		(net "M_C_CPU0_SB_DQS_DN<5>")
	)
	(segment
		(start 306.703476 -233.20248)
		(end 305.73091 -233.20248)
		(width 0.18288)
		(layer "In6.Cu")
		(net "M_C_CPU0_SB_DQS_DN<5>")
	)
	(segment
		(start 343.790524 -241.970052)
		(end 343.778586 -241.96294)
		(width 0.088646)
		(layer "In6.Cu")
		(net "M_C_CPU0_SB_DQS_DN<5>")
	)
	(segment
		(start 334.392778 -241.970052)
		(end 334.38084 -241.96294)
		(width 0.088646)
		(layer "In6.Cu")
		(net "M_C_CPU0_SB_DQS_DN<5>")
	)
	(segment
		(start 334.970628 -241.96294)
		(end 334.95869 -241.970052)
		(width 0.088646)
		(layer "In6.Cu")
		(net "M_C_CPU0_SB_DQS_DN<5>")
	)
	(segment
		(start 293.765478 -231.45623)
		(end 292.999414 -230.690166)
		(width 0.18288)
		(layer "In6.Cu")
		(net "M_C_CPU0_SB_DQS_DN<5>")
	)
	(segment
		(start 308.513734 -234.072684)
		(end 308.389274 -233.948224)
		(width 0.18288)
		(layer "In6.Cu")
		(net "M_C_CPU0_SB_DQS_DN<5>")
	)
	(segment
		(start 305.60645 -233.32694)
		(end 305.05781 -233.32694)
		(width 0.18288)
		(layer "In6.Cu")
		(net "M_C_CPU0_SB_DQS_DN<5>")
	)
	(segment
		(start 332.422246 -241.740944)
		(end 332.30185 -241.620548)
		(width 0.088646)
		(layer "In6.Cu")
		(net "M_C_CPU0_SB_DQS_DN<5>")
	)
	(segment
		(start 297.289474 -231.72039)
		(end 296.226738 -231.72039)
		(width 0.18288)
		(layer "In6.Cu")
		(net "M_C_CPU0_SB_DQS_DN<5>")
	)
	(segment
		(start 309.062374 -234.072684)
		(end 308.513734 -234.072684)
		(width 0.18288)
		(layer "In6.Cu")
		(net "M_C_CPU0_SB_DQS_DN<5>")
	)
	(segment
		(start 340.031324 -241.970052)
		(end 340.019386 -241.96294)
		(width 0.088646)
		(layer "In6.Cu")
		(net "M_C_CPU0_SB_DQS_DN<5>")
	)
	(segment
		(start 313.649614 -236.331506)
		(end 312.410094 -235.091986)
		(width 0.18288)
		(layer "In6.Cu")
		(net "M_C_CPU0_SB_DQS_DN<5>")
	)
	(segment
		(start 307.44922 -233.948224)
		(end 306.703476 -233.20248)
		(width 0.18288)
		(layer "In6.Cu")
		(net "M_C_CPU0_SB_DQS_DN<5>")
	)
	(segment
		(start 308.389274 -233.948224)
		(end 307.44922 -233.948224)
		(width 0.18288)
		(layer "In6.Cu")
		(net "M_C_CPU0_SB_DQS_DN<5>")
	)
	(segment
		(start 344.913712 -242.237768)
		(end 344.913966 -242.237768)
		(width 0.088646)
		(layer "In6.Cu")
		(net "M_C_CPU0_SB_DQS_DN<5>")
	)
	(segment
		(start 294.420798 -231.45623)
		(end 293.765478 -231.45623)
		(width 0.18288)
		(layer "In6.Cu")
		(net "M_C_CPU0_SB_DQS_DN<5>")
	)
	(segment
		(start 296.226738 -231.72039)
		(end 295.96842 -231.462072)
		(width 0.18288)
		(layer "In6.Cu")
		(net "M_C_CPU0_SB_DQS_DN<5>")
	)
	(segment
		(start 302.942498 -232.334308)
		(end 299.5422 -232.334308)
		(width 0.18288)
		(layer "In6.Cu")
		(net "M_C_CPU0_SB_DQS_DN<5>")
	)
	(segment
		(start 333.470504 -241.98072)
		(end 333.433928 -241.959384)
		(width 0.088646)
		(layer "In6.Cu")
		(net "M_C_CPU0_SB_DQS_DN<5>")
	)
	(segment
		(start 303.81067 -233.20248)
		(end 302.942498 -232.334308)
		(width 0.18288)
		(layer "In6.Cu")
		(net "M_C_CPU0_SB_DQS_DN<5>")
	)
	(segment
		(start 297.875198 -232.306114)
		(end 297.289474 -231.72039)
		(width 0.18288)
		(layer "In6.Cu")
		(net "M_C_CPU0_SB_DQS_DN<5>")
	)
	(segment
		(start 344.856562 -242.294918)
		(end 344.913712 -242.237768)
		(width 0.088646)
		(layer "In6.Cu")
		(net "M_C_CPU0_SB_DQS_DN<5>")
	)
	(segment
		(start 299.284644 -232.591864)
		(end 298.806616 -232.591864)
		(width 0.18288)
		(layer "In6.Cu")
		(net "M_C_CPU0_SB_DQS_DN<5>")
	)
	(segment
		(start 304.93335 -233.20248)
		(end 303.81067 -233.20248)
		(width 0.18288)
		(layer "In6.Cu")
		(net "M_C_CPU0_SB_DQS_DN<5>")
	)
	(segment
		(start 305.73091 -233.20248)
		(end 305.60645 -233.32694)
		(width 0.18288)
		(layer "In6.Cu")
		(net "M_C_CPU0_SB_DQS_DN<5>")
	)
	(segment
		(start 319.60185 -240.618264)
		(end 315.315092 -236.331506)
		(width 0.18288)
		(layer "In6.Cu")
		(net "M_C_CPU0_SB_DQS_DN<5>")
	)
	(segment
		(start 344.543634 -242.294918)
		(end 344.856562 -242.294918)
		(width 0.088646)
		(layer "In6.Cu")
		(net "M_C_CPU0_SB_DQS_DN<5>")
	)
	(segment
		(start 337.211924 -241.970052)
		(end 337.199986 -241.96294)
		(width 0.088646)
		(layer "In6.Cu")
		(net "M_C_CPU0_SB_DQS_DN<5>")
	)
	(segment
		(start 299.5422 -232.334308)
		(end 299.284644 -232.591864)
		(width 0.18288)
		(layer "In6.Cu")
		(net "M_C_CPU0_SB_DQS_DN<5>")
	)
	(segment
		(start 298.806616 -232.591864)
		(end 298.520866 -232.306114)
		(width 0.18288)
		(layer "In6.Cu")
		(net "M_C_CPU0_SB_DQS_DN<5>")
	)
	(segment
		(start 295.464484 -231.462072)
		(end 295.18483 -231.741726)
		(width 0.18288)
		(layer "In6.Cu")
		(net "M_C_CPU0_SB_DQS_DN<5>")
	)
	(segment
		(start 341.911178 -241.970052)
		(end 341.902796 -241.965226)
		(width 0.088646)
		(layer "In6.Cu")
		(net "M_C_CPU0_SB_DQS_DN<5>")
	)
	(segment
		(start 311.809638 -235.091986)
		(end 310.665876 -233.948224)
		(width 0.18288)
		(layer "In6.Cu")
		(net "M_C_CPU0_SB_DQS_DN<5>")
	)
	(segment
		(start 294.706294 -231.741726)
		(end 294.420798 -231.45623)
		(width 0.18288)
		(layer "In6.Cu")
		(net "M_C_CPU0_SB_DQS_DN<5>")
	)
	(segment
		(start 331.029564 -240.618264)
		(end 319.60185 -240.618264)
		(width 0.18288)
		(layer "In6.Cu")
		(net "M_C_CPU0_SB_DQS_DN<5>")
	)
	(segment
		(start 285.762446 -227.817426)
		(end 284.694884 -227.817426)
		(width 0.18288)
		(layer "In6.Cu")
		(net "M_C_CPU0_SB_DQS_DN<5>")
	)
	(segment
		(start 286.92348 -228.97846)
		(end 285.762446 -227.817426)
		(width 0.18288)
		(layer "In6.Cu")
		(net "M_C_CPU0_SB_DQS_DN<5>")
	)
	(segment
		(start 331.343508 -240.558574)
		(end 331.112622 -240.558574)
		(width 0.088646)
		(layer "In6.Cu")
		(net "M_C_CPU0_SB_DQS_DN<5>")
	)
	(arc
		(start 339.079586 -241.96294)
		(mid 338.897416 -241.919951)
		(end 338.717128 -241.970306)
		(width 0.088646)
		(layer "In6.Cu")
		(net "M_C_CPU0_SB_DQS_DN<5>")
	)
	(arc
		(start 343.416128 -241.970306)
		(mid 343.133397 -242.045989)
		(end 342.850724 -241.970052)
		(width 0.088646)
		(layer "In6.Cu")
		(net "M_C_CPU0_SB_DQS_DN<5>")
	)
	(arc
		(start 335.897982 -241.970306)
		(mid 335.615534 -242.045989)
		(end 335.333086 -241.970306)
		(width 0.088646)
		(layer "In6.Cu")
		(net "M_C_CPU0_SB_DQS_DN<5>")
	)
	(arc
		(start 338.139786 -241.96294)
		(mid 337.957616 -241.919951)
		(end 337.777328 -241.970306)
		(width 0.088646)
		(layer "In6.Cu")
		(net "M_C_CPU0_SB_DQS_DN<5>")
	)
	(arc
		(start 334.017874 -241.970306)
		(mid 333.74552 -242.046266)
		(end 333.470504 -241.98072)
		(width 0.088646)
		(layer "In6.Cu")
		(net "M_C_CPU0_SB_DQS_DN<5>")
	)
	(arc
		(start 343.778586 -241.96294)
		(mid 343.596416 -241.919951)
		(end 343.416128 -241.970306)
		(width 0.088646)
		(layer "In6.Cu")
		(net "M_C_CPU0_SB_DQS_DN<5>")
	)
	(arc
		(start 341.536528 -241.970306)
		(mid 341.253797 -242.045989)
		(end 340.971124 -241.970052)
		(width 0.088646)
		(layer "In6.Cu")
		(net "M_C_CPU0_SB_DQS_DN<5>")
	)
	(arc
		(start 344.913966 -242.237768)
		(mid 344.854636 -242.085898)
		(end 344.73642 -241.973608)
		(width 0.088646)
		(layer "In6.Cu")
		(net "M_C_CPU0_SB_DQS_DN<5>")
	)
	(arc
		(start 333.163164 -241.93373)
		(mid 332.766513 -241.938039)
		(end 332.422246 -241.740944)
		(width 0.088646)
		(layer "In6.Cu")
		(net "M_C_CPU0_SB_DQS_DN<5>")
	)
	(arc
		(start 340.596728 -241.970306)
		(mid 340.313997 -242.045989)
		(end 340.031324 -241.970052)
		(width 0.088646)
		(layer "In6.Cu")
		(net "M_C_CPU0_SB_DQS_DN<5>")
	)
	(arc
		(start 342.476582 -241.970306)
		(mid 342.193851 -242.045989)
		(end 341.911178 -241.970052)
		(width 0.088646)
		(layer "In6.Cu")
		(net "M_C_CPU0_SB_DQS_DN<5>")
	)
	(arc
		(start 336.837528 -241.970306)
		(mid 336.560939 -242.045959)
		(end 336.282792 -241.976148)
		(width 0.088646)
		(layer "In6.Cu")
		(net "M_C_CPU0_SB_DQS_DN<5>")
	)
	(arc
		(start 339.656928 -241.970306)
		(mid 339.374197 -242.045989)
		(end 339.091524 -241.970052)
		(width 0.088646)
		(layer "In6.Cu")
		(net "M_C_CPU0_SB_DQS_DN<5>")
	)
	(arc
		(start 337.199986 -241.96294)
		(mid 337.017816 -241.919951)
		(end 336.837528 -241.970306)
		(width 0.088646)
		(layer "In6.Cu")
		(net "M_C_CPU0_SB_DQS_DN<5>")
	)
	(arc
		(start 340.019386 -241.96294)
		(mid 339.837216 -241.919951)
		(end 339.656928 -241.970306)
		(width 0.088646)
		(layer "In6.Cu")
		(net "M_C_CPU0_SB_DQS_DN<5>")
	)
	(arc
		(start 338.717128 -241.970306)
		(mid 338.434397 -242.045989)
		(end 338.151724 -241.970052)
		(width 0.088646)
		(layer "In6.Cu")
		(net "M_C_CPU0_SB_DQS_DN<5>")
	)
	(arc
		(start 344.355928 -241.970306)
		(mid 344.073197 -242.045989)
		(end 343.790524 -241.970052)
		(width 0.088646)
		(layer "In6.Cu")
		(net "M_C_CPU0_SB_DQS_DN<5>")
	)
	(arc
		(start 342.842342 -241.965226)
		(mid 342.658804 -241.920134)
		(end 342.476582 -241.970306)
		(width 0.088646)
		(layer "In6.Cu")
		(net "M_C_CPU0_SB_DQS_DN<5>")
	)
	(arc
		(start 333.433928 -241.959384)
		(mid 333.30095 -241.92117)
		(end 333.163164 -241.93373)
		(width 0.088646)
		(layer "In6.Cu")
		(net "M_C_CPU0_SB_DQS_DN<5>")
	)
	(arc
		(start 340.959186 -241.96294)
		(mid 340.777016 -241.919951)
		(end 340.596728 -241.970306)
		(width 0.088646)
		(layer "In6.Cu")
		(net "M_C_CPU0_SB_DQS_DN<5>")
	)
	(arc
		(start 334.95869 -241.970052)
		(mid 334.675734 -242.046023)
		(end 334.392778 -241.970052)
		(width 0.088646)
		(layer "In6.Cu")
		(net "M_C_CPU0_SB_DQS_DN<5>")
	)
	(arc
		(start 335.333086 -241.970306)
		(mid 335.152799 -241.919894)
		(end 334.970628 -241.96294)
		(width 0.088646)
		(layer "In6.Cu")
		(net "M_C_CPU0_SB_DQS_DN<5>")
	)
	(arc
		(start 334.38084 -241.96294)
		(mid 334.198416 -241.919833)
		(end 334.017874 -241.970306)
		(width 0.088646)
		(layer "In6.Cu")
		(net "M_C_CPU0_SB_DQS_DN<5>")
	)
	(arc
		(start 341.902796 -241.965226)
		(mid 341.719004 -241.920013)
		(end 341.536528 -241.970306)
		(width 0.088646)
		(layer "In6.Cu")
		(net "M_C_CPU0_SB_DQS_DN<5>")
	)
	(arc
		(start 332.30185 -241.620548)
		(mid 332.217802 -241.518344)
		(end 332.155038 -241.401854)
		(width 0.088646)
		(layer "In6.Cu")
		(net "M_C_CPU0_SB_DQS_DN<5>")
	)
	(arc
		(start 336.260694 -241.963194)
		(mid 336.078409 -241.919931)
		(end 335.897982 -241.970306)
		(width 0.088646)
		(layer "In6.Cu")
		(net "M_C_CPU0_SB_DQS_DN<5>")
	)
	(arc
		(start 344.730832 -241.97056)
		(mid 344.543634 -241.920417)
		(end 344.356436 -241.97056)
		(width 0.088646)
		(layer "In6.Cu")
		(net "M_C_CPU0_SB_DQS_DN<5>")
	)
	(arc
		(start 337.777328 -241.970306)
		(mid 337.494597 -242.045989)
		(end 337.211924 -241.970052)
		(width 0.088646)
		(layer "In6.Cu")
		(net "M_C_CPU0_SB_DQS_DN<5>")
	)
	(arc
		(start 332.155038 -241.401854)
		(mid 332.127009 -241.350024)
		(end 332.089506 -241.304572)
		(width 0.088646)
		(layer "In6.Cu")
		(net "M_C_CPU0_SB_DQS_DN<5>")
	)
	(segment
		(start 276.000972 -237.005622)
		(end 275.73986 -237.266734)
		(width 0.20066)
		(layer "F.Cu")
		(net "M_C_CPU0_SB_DQS_DN<4>")
	)
	(segment
		(start 341.254334 -240.389156)
		(end 341.254334 -239.85347)
		(width 0.20066)
		(layer "F.Cu")
		(net "M_C_CPU0_SB_DQS_DN<4>")
	)
	(segment
		(start 276.896576 -236.58322)
		(end 276.474174 -237.005622)
		(width 0.20066)
		(layer "F.Cu")
		(net "M_C_CPU0_SB_DQS_DN<4>")
	)
	(segment
		(start 279.965404 -236.841792)
		(end 279.912826 -236.841792)
		(width 0.101854)
		(layer "F.Cu")
		(net "M_C_CPU0_SB_DQS_DN<4>")
	)
	(segment
		(start 280.316178 -236.58068)
		(end 280.055066 -236.841792)
		(width 0.20066)
		(layer "F.Cu")
		(net "M_C_CPU0_SB_DQS_DN<4>")
	)
	(segment
		(start 341.254334 -239.85347)
		(end 341.25408 -239.853216)
		(width 0.20066)
		(layer "F.Cu")
		(net "M_C_CPU0_SB_DQS_DN<4>")
	)
	(segment
		(start 280.055066 -236.841792)
		(end 279.965404 -236.841792)
		(width 0.20066)
		(layer "F.Cu")
		(net "M_C_CPU0_SB_DQS_DN<4>")
	)
	(segment
		(start 276.474174 -237.005622)
		(end 276.000972 -237.005622)
		(width 0.20066)
		(layer "F.Cu")
		(net "M_C_CPU0_SB_DQS_DN<4>")
	)
	(segment
		(start 281.356816 -237.005622)
		(end 280.7208 -236.58068)
		(width 0.20066)
		(layer "F.Cu")
		(net "M_C_CPU0_SB_DQS_DN<4>")
	)
	(segment
		(start 282.811982 -237.266734)
		(end 282.321508 -237.266734)
		(width 0.20066)
		(layer "F.Cu")
		(net "M_C_CPU0_SB_DQS_DN<4>")
	)
	(segment
		(start 277.136352 -236.58322)
		(end 276.896576 -236.58322)
		(width 0.20066)
		(layer "F.Cu")
		(net "M_C_CPU0_SB_DQS_DN<4>")
	)
	(segment
		(start 277.83536 -236.841792)
		(end 277.444708 -236.841792)
		(width 0.101854)
		(layer "F.Cu")
		(net "M_C_CPU0_SB_DQS_DN<4>")
	)
	(segment
		(start 280.7208 -236.58068)
		(end 280.316178 -236.58068)
		(width 0.20066)
		(layer "F.Cu")
		(net "M_C_CPU0_SB_DQS_DN<4>")
	)
	(segment
		(start 275.73986 -237.266734)
		(end 275.268182 -237.266734)
		(width 0.20066)
		(layer "F.Cu")
		(net "M_C_CPU0_SB_DQS_DN<4>")
	)
	(segment
		(start 279.912826 -236.841792)
		(end 277.83536 -236.841792)
		(width 0.1016)
		(layer "F.Cu")
		(net "M_C_CPU0_SB_DQS_DN<4>")
	)
	(segment
		(start 282.321508 -237.266734)
		(end 282.060396 -237.005622)
		(width 0.20066)
		(layer "F.Cu")
		(net "M_C_CPU0_SB_DQS_DN<4>")
	)
	(segment
		(start 282.060396 -237.005622)
		(end 281.356816 -237.005622)
		(width 0.20066)
		(layer "F.Cu")
		(net "M_C_CPU0_SB_DQS_DN<4>")
	)
	(segment
		(start 283.916882 -237.266734)
		(end 282.811982 -237.266734)
		(width 0.20066)
		(layer "F.Cu")
		(net "M_C_CPU0_SB_DQS_DN<4>")
	)
	(segment
		(start 277.394924 -236.841792)
		(end 277.136352 -236.58322)
		(width 0.20066)
		(layer "F.Cu")
		(net "M_C_CPU0_SB_DQS_DN<4>")
	)
	(segment
		(start 277.444708 -236.841792)
		(end 277.394924 -236.841792)
		(width 0.20066)
		(layer "F.Cu")
		(net "M_C_CPU0_SB_DQS_DN<4>")
	)
	(segment
		(start 284.57525 -236.995208)
		(end 284.188408 -236.995208)
		(width 0.18288)
		(layer "In4.Cu")
		(net "M_C_CPU0_SB_DQS_DN<4>")
	)
	(segment
		(start 316.924182 -238.706406)
		(end 316.74816 -238.706406)
		(width 0.18288)
		(layer "In4.Cu")
		(net "M_C_CPU0_SB_DQS_DN<4>")
	)
	(segment
		(start 332.154022 -240.418874)
		(end 331.85481 -240.718086)
		(width 0.088646)
		(layer "In4.Cu")
		(net "M_C_CPU0_SB_DQS_DN<4>")
	)
	(segment
		(start 298.53382 -235.716572)
		(end 298.208446 -235.716572)
		(width 0.18288)
		(layer "In4.Cu")
		(net "M_C_CPU0_SB_DQS_DN<4>")
	)
	(segment
		(start 334.486758 -239.52962)
		(end 334.479392 -239.533938)
		(width 0.088646)
		(layer "In4.Cu")
		(net "M_C_CPU0_SB_DQS_DN<4>")
	)
	(segment
		(start 331.04582 -240.77803)
		(end 331.004164 -240.77803)
		(width 0.088646)
		(layer "In4.Cu")
		(net "M_C_CPU0_SB_DQS_DN<4>")
	)
	(segment
		(start 331.105764 -240.718086)
		(end 331.04582 -240.77803)
		(width 0.088646)
		(layer "In4.Cu")
		(net "M_C_CPU0_SB_DQS_DN<4>")
	)
	(segment
		(start 301.103284 -236.391196)
		(end 301.103284 -236.215174)
		(width 0.18288)
		(layer "In4.Cu")
		(net "M_C_CPU0_SB_DQS_DN<4>")
	)
	(segment
		(start 292.352984 -235.957618)
		(end 291.91331 -236.397292)
		(width 0.18288)
		(layer "In4.Cu")
		(net "M_C_CPU0_SB_DQS_DN<4>")
	)
	(segment
		(start 309.64886 -237.038134)
		(end 309.472838 -237.038134)
		(width 0.18288)
		(layer "In4.Cu")
		(net "M_C_CPU0_SB_DQS_DN<4>")
	)
	(segment
		(start 331.85481 -240.718086)
		(end 331.105764 -240.718086)
		(width 0.088646)
		(layer "In4.Cu")
		(net "M_C_CPU0_SB_DQS_DN<4>")
	)
	(segment
		(start 284.788356 -237.208314)
		(end 284.57525 -236.995208)
		(width 0.18288)
		(layer "In4.Cu")
		(net "M_C_CPU0_SB_DQS_DN<4>")
	)
	(segment
		(start 335.428082 -239.528858)
		(end 335.41335 -239.537494)
		(width 0.088646)
		(layer "In4.Cu")
		(net "M_C_CPU0_SB_DQS_DN<4>")
	)
	(segment
		(start 309.084472 -236.649768)
		(end 309.084472 -236.473746)
		(width 0.18288)
		(layer "In4.Cu")
		(net "M_C_CPU0_SB_DQS_DN<4>")
	)
	(segment
		(start 291.36467 -236.397292)
		(end 291.24021 -236.521752)
		(width 0.18288)
		(layer "In4.Cu")
		(net "M_C_CPU0_SB_DQS_DN<4>")
	)
	(segment
		(start 341.25408 -239.853216)
		(end 340.90356 -239.644428)
		(width 0.088646)
		(layer "In4.Cu")
		(net "M_C_CPU0_SB_DQS_DN<4>")
	)
	(segment
		(start 334.488282 -239.528858)
		(end 334.486758 -239.52962)
		(width 0.088646)
		(layer "In4.Cu")
		(net "M_C_CPU0_SB_DQS_DN<4>")
	)
	(segment
		(start 293.61257 -236.574584)
		(end 292.995604 -235.957618)
		(width 0.18288)
		(layer "In4.Cu")
		(net "M_C_CPU0_SB_DQS_DN<4>")
	)
	(segment
		(start 313.770518 -237.447582)
		(end 313.646058 -237.572042)
		(width 0.18288)
		(layer "In4.Cu")
		(net "M_C_CPU0_SB_DQS_DN<4>")
	)
	(segment
		(start 308.605174 -235.994448)
		(end 307.495448 -235.994448)
		(width 0.18288)
		(layer "In4.Cu")
		(net "M_C_CPU0_SB_DQS_DN<4>")
	)
	(segment
		(start 331.004164 -240.77803)
		(end 318.995806 -240.77803)
		(width 0.18288)
		(layer "In4.Cu")
		(net "M_C_CPU0_SB_DQS_DN<4>")
	)
	(segment
		(start 315.665358 -237.447582)
		(end 315.116718 -237.447582)
		(width 0.18288)
		(layer "In4.Cu")
		(net "M_C_CPU0_SB_DQS_DN<4>")
	)
	(segment
		(start 294.443912 -236.574584)
		(end 293.61257 -236.574584)
		(width 0.18288)
		(layer "In4.Cu")
		(net "M_C_CPU0_SB_DQS_DN<4>")
	)
	(segment
		(start 311.626758 -237.447582)
		(end 310.058308 -237.447582)
		(width 0.18288)
		(layer "In4.Cu")
		(net "M_C_CPU0_SB_DQS_DN<4>")
	)
	(segment
		(start 333.467964 -240.351564)
		(end 333.453232 -240.342928)
		(width 0.088646)
		(layer "In4.Cu")
		(net "M_C_CPU0_SB_DQS_DN<4>")
	)
	(segment
		(start 299.185076 -235.991908)
		(end 298.809156 -235.991908)
		(width 0.18288)
		(layer "In4.Cu")
		(net "M_C_CPU0_SB_DQS_DN<4>")
	)
	(segment
		(start 318.995806 -240.77803)
		(end 316.924182 -238.706406)
		(width 0.18288)
		(layer "In4.Cu")
		(net "M_C_CPU0_SB_DQS_DN<4>")
	)
	(segment
		(start 332.79588 -240.418874)
		(end 332.154022 -240.418874)
		(width 0.088646)
		(layer "In4.Cu")
		(net "M_C_CPU0_SB_DQS_DN<4>")
	)
	(segment
		(start 298.208446 -235.716572)
		(end 297.358562 -236.566456)
		(width 0.18288)
		(layer "In4.Cu")
		(net "M_C_CPU0_SB_DQS_DN<4>")
	)
	(segment
		(start 286.532066 -237.332774)
		(end 286.407606 -237.208314)
		(width 0.18288)
		(layer "In4.Cu")
		(net "M_C_CPU0_SB_DQS_DN<4>")
	)
	(segment
		(start 307.495448 -235.994448)
		(end 306.949602 -236.540294)
		(width 0.18288)
		(layer "In4.Cu")
		(net "M_C_CPU0_SB_DQS_DN<4>")
	)
	(segment
		(start 340.127082 -239.528858)
		(end 340.11235 -239.537494)
		(width 0.088646)
		(layer "In4.Cu")
		(net "M_C_CPU0_SB_DQS_DN<4>")
	)
	(segment
		(start 303.05248 -237.167166)
		(end 302.055276 -237.167166)
		(width 0.18288)
		(layer "In4.Cu")
		(net "M_C_CPU0_SB_DQS_DN<4>")
	)
	(segment
		(start 290.69157 -236.521752)
		(end 290.56711 -236.397292)
		(width 0.18288)
		(layer "In4.Cu")
		(net "M_C_CPU0_SB_DQS_DN<4>")
	)
	(segment
		(start 287.205166 -237.208314)
		(end 287.080706 -237.332774)
		(width 0.18288)
		(layer "In4.Cu")
		(net "M_C_CPU0_SB_DQS_DN<4>")
	)
	(segment
		(start 297.358562 -236.566456)
		(end 295.358312 -236.566456)
		(width 0.18288)
		(layer "In4.Cu")
		(net "M_C_CPU0_SB_DQS_DN<4>")
	)
	(segment
		(start 300.61408 -235.72597)
		(end 299.451014 -235.72597)
		(width 0.18288)
		(layer "In4.Cu")
		(net "M_C_CPU0_SB_DQS_DN<4>")
	)
	(segment
		(start 314.319158 -237.447582)
		(end 313.770518 -237.447582)
		(width 0.18288)
		(layer "In4.Cu")
		(net "M_C_CPU0_SB_DQS_DN<4>")
	)
	(segment
		(start 301.491396 -236.779308)
		(end 301.103284 -236.391196)
		(width 0.18288)
		(layer "In4.Cu")
		(net "M_C_CPU0_SB_DQS_DN<4>")
	)
	(segment
		(start 336.367882 -239.528858)
		(end 336.35315 -239.537494)
		(width 0.088646)
		(layer "In4.Cu")
		(net "M_C_CPU0_SB_DQS_DN<4>")
	)
	(segment
		(start 301.103284 -236.215174)
		(end 300.61408 -235.72597)
		(width 0.18288)
		(layer "In4.Cu")
		(net "M_C_CPU0_SB_DQS_DN<4>")
	)
	(segment
		(start 306.949602 -236.540294)
		(end 303.679352 -236.540294)
		(width 0.18288)
		(layer "In4.Cu")
		(net "M_C_CPU0_SB_DQS_DN<4>")
	)
	(segment
		(start 289.89401 -236.521752)
		(end 289.34537 -236.521752)
		(width 0.18288)
		(layer "In4.Cu")
		(net "M_C_CPU0_SB_DQS_DN<4>")
	)
	(segment
		(start 309.084472 -236.473746)
		(end 308.605174 -235.994448)
		(width 0.18288)
		(layer "In4.Cu")
		(net "M_C_CPU0_SB_DQS_DN<4>")
	)
	(segment
		(start 294.71112 -236.841792)
		(end 294.443912 -236.574584)
		(width 0.18288)
		(layer "In4.Cu")
		(net "M_C_CPU0_SB_DQS_DN<4>")
	)
	(segment
		(start 287.080706 -237.332774)
		(end 286.532066 -237.332774)
		(width 0.18288)
		(layer "In4.Cu")
		(net "M_C_CPU0_SB_DQS_DN<4>")
	)
	(segment
		(start 291.24021 -236.521752)
		(end 290.69157 -236.521752)
		(width 0.18288)
		(layer "In4.Cu")
		(net "M_C_CPU0_SB_DQS_DN<4>")
	)
	(segment
		(start 292.995604 -235.957618)
		(end 292.352984 -235.957618)
		(width 0.18288)
		(layer "In4.Cu")
		(net "M_C_CPU0_SB_DQS_DN<4>")
	)
	(segment
		(start 314.992258 -237.572042)
		(end 314.443618 -237.572042)
		(width 0.18288)
		(layer "In4.Cu")
		(net "M_C_CPU0_SB_DQS_DN<4>")
	)
	(segment
		(start 301.667418 -236.779308)
		(end 301.491396 -236.779308)
		(width 0.18288)
		(layer "In4.Cu")
		(net "M_C_CPU0_SB_DQS_DN<4>")
	)
	(segment
		(start 284.188408 -236.995208)
		(end 283.916882 -237.266734)
		(width 0.18288)
		(layer "In4.Cu")
		(net "M_C_CPU0_SB_DQS_DN<4>")
	)
	(segment
		(start 334.30083 -239.853216)
		(end 334.30083 -239.875314)
		(width 0.088646)
		(layer "In4.Cu")
		(net "M_C_CPU0_SB_DQS_DN<4>")
	)
	(segment
		(start 303.679352 -236.540294)
		(end 303.05248 -237.167166)
		(width 0.18288)
		(layer "In4.Cu")
		(net "M_C_CPU0_SB_DQS_DN<4>")
	)
	(segment
		(start 288.564828 -236.397292)
		(end 287.753806 -237.208314)
		(width 0.18288)
		(layer "In4.Cu")
		(net "M_C_CPU0_SB_DQS_DN<4>")
	)
	(segment
		(start 316.359794 -238.31804)
		(end 316.359794 -238.142018)
		(width 0.18288)
		(layer "In4.Cu")
		(net "M_C_CPU0_SB_DQS_DN<4>")
	)
	(segment
		(start 309.472838 -237.038134)
		(end 309.084472 -236.649768)
		(width 0.18288)
		(layer "In4.Cu")
		(net "M_C_CPU0_SB_DQS_DN<4>")
	)
	(segment
		(start 316.74816 -238.706406)
		(end 316.359794 -238.31804)
		(width 0.18288)
		(layer "In4.Cu")
		(net "M_C_CPU0_SB_DQS_DN<4>")
	)
	(segment
		(start 286.407606 -237.208314)
		(end 284.788356 -237.208314)
		(width 0.18288)
		(layer "In4.Cu")
		(net "M_C_CPU0_SB_DQS_DN<4>")
	)
	(segment
		(start 310.058308 -237.447582)
		(end 309.64886 -237.038134)
		(width 0.18288)
		(layer "In4.Cu")
		(net "M_C_CPU0_SB_DQS_DN<4>")
	)
	(segment
		(start 295.358312 -236.566456)
		(end 295.082976 -236.841792)
		(width 0.18288)
		(layer "In4.Cu")
		(net "M_C_CPU0_SB_DQS_DN<4>")
	)
	(segment
		(start 289.22091 -236.397292)
		(end 288.564828 -236.397292)
		(width 0.18288)
		(layer "In4.Cu")
		(net "M_C_CPU0_SB_DQS_DN<4>")
	)
	(segment
		(start 299.451014 -235.72597)
		(end 299.185076 -235.991908)
		(width 0.18288)
		(layer "In4.Cu")
		(net "M_C_CPU0_SB_DQS_DN<4>")
	)
	(segment
		(start 295.082976 -236.841792)
		(end 294.71112 -236.841792)
		(width 0.18288)
		(layer "In4.Cu")
		(net "M_C_CPU0_SB_DQS_DN<4>")
	)
	(segment
		(start 314.443618 -237.572042)
		(end 314.319158 -237.447582)
		(width 0.18288)
		(layer "In4.Cu")
		(net "M_C_CPU0_SB_DQS_DN<4>")
	)
	(segment
		(start 337.307682 -239.528858)
		(end 337.29295 -239.537494)
		(width 0.088646)
		(layer "In4.Cu")
		(net "M_C_CPU0_SB_DQS_DN<4>")
	)
	(segment
		(start 312.972958 -237.447582)
		(end 312.424318 -237.447582)
		(width 0.18288)
		(layer "In4.Cu")
		(net "M_C_CPU0_SB_DQS_DN<4>")
	)
	(segment
		(start 287.753806 -237.208314)
		(end 287.205166 -237.208314)
		(width 0.18288)
		(layer "In4.Cu")
		(net "M_C_CPU0_SB_DQS_DN<4>")
	)
	(segment
		(start 290.56711 -236.397292)
		(end 290.01847 -236.397292)
		(width 0.18288)
		(layer "In4.Cu")
		(net "M_C_CPU0_SB_DQS_DN<4>")
	)
	(segment
		(start 339.187282 -239.528858)
		(end 339.176868 -239.534954)
		(width 0.088646)
		(layer "In4.Cu")
		(net "M_C_CPU0_SB_DQS_DN<4>")
	)
	(segment
		(start 289.34537 -236.521752)
		(end 289.22091 -236.397292)
		(width 0.18288)
		(layer "In4.Cu")
		(net "M_C_CPU0_SB_DQS_DN<4>")
	)
	(segment
		(start 313.097418 -237.572042)
		(end 312.972958 -237.447582)
		(width 0.18288)
		(layer "In4.Cu")
		(net "M_C_CPU0_SB_DQS_DN<4>")
	)
	(segment
		(start 311.751218 -237.572042)
		(end 311.626758 -237.447582)
		(width 0.18288)
		(layer "In4.Cu")
		(net "M_C_CPU0_SB_DQS_DN<4>")
	)
	(segment
		(start 338.247736 -239.528858)
		(end 338.237322 -239.534954)
		(width 0.088646)
		(layer "In4.Cu")
		(net "M_C_CPU0_SB_DQS_DN<4>")
	)
	(segment
		(start 298.809156 -235.991908)
		(end 298.53382 -235.716572)
		(width 0.18288)
		(layer "In4.Cu")
		(net "M_C_CPU0_SB_DQS_DN<4>")
	)
	(segment
		(start 315.116718 -237.447582)
		(end 314.992258 -237.572042)
		(width 0.18288)
		(layer "In4.Cu")
		(net "M_C_CPU0_SB_DQS_DN<4>")
	)
	(segment
		(start 291.91331 -236.397292)
		(end 291.36467 -236.397292)
		(width 0.18288)
		(layer "In4.Cu")
		(net "M_C_CPU0_SB_DQS_DN<4>")
	)
	(segment
		(start 313.646058 -237.572042)
		(end 313.097418 -237.572042)
		(width 0.18288)
		(layer "In4.Cu")
		(net "M_C_CPU0_SB_DQS_DN<4>")
	)
	(segment
		(start 312.299858 -237.572042)
		(end 311.751218 -237.572042)
		(width 0.18288)
		(layer "In4.Cu")
		(net "M_C_CPU0_SB_DQS_DN<4>")
	)
	(segment
		(start 312.424318 -237.447582)
		(end 312.299858 -237.572042)
		(width 0.18288)
		(layer "In4.Cu")
		(net "M_C_CPU0_SB_DQS_DN<4>")
	)
	(segment
		(start 290.01847 -236.397292)
		(end 289.89401 -236.521752)
		(width 0.18288)
		(layer "In4.Cu")
		(net "M_C_CPU0_SB_DQS_DN<4>")
	)
	(segment
		(start 316.359794 -238.142018)
		(end 315.665358 -237.447582)
		(width 0.18288)
		(layer "In4.Cu")
		(net "M_C_CPU0_SB_DQS_DN<4>")
	)
	(segment
		(start 302.055276 -237.167166)
		(end 301.667418 -236.779308)
		(width 0.18288)
		(layer "In4.Cu")
		(net "M_C_CPU0_SB_DQS_DN<4>")
	)
	(arc
		(start 334.479392 -239.533938)
		(mid 334.348478 -239.670298)
		(end 334.30083 -239.853216)
		(width 0.088646)
		(layer "In4.Cu")
		(net "M_C_CPU0_SB_DQS_DN<4>")
	)
	(arc
		(start 336.742278 -239.528858)
		(mid 336.55508 -239.478715)
		(end 336.367882 -239.528858)
		(width 0.088646)
		(layer "In4.Cu")
		(net "M_C_CPU0_SB_DQS_DN<4>")
	)
	(arc
		(start 339.176868 -239.534954)
		(mid 338.89869 -239.604677)
		(end 338.622132 -239.528858)
		(width 0.088646)
		(layer "In4.Cu")
		(net "M_C_CPU0_SB_DQS_DN<4>")
	)
	(arc
		(start 340.767416 -239.604804)
		(mid 340.629727 -239.583354)
		(end 340.501478 -239.528858)
		(width 0.088646)
		(layer "In4.Cu")
		(net "M_C_CPU0_SB_DQS_DN<4>")
	)
	(arc
		(start 333.078836 -240.342928)
		(mid 332.942363 -240.399562)
		(end 332.79588 -240.418874)
		(width 0.088646)
		(layer "In4.Cu")
		(net "M_C_CPU0_SB_DQS_DN<4>")
	)
	(arc
		(start 340.11235 -239.537494)
		(mid 339.835875 -239.604814)
		(end 339.561678 -239.528858)
		(width 0.088646)
		(layer "In4.Cu")
		(net "M_C_CPU0_SB_DQS_DN<4>")
	)
	(arc
		(start 333.453232 -240.342928)
		(mid 333.266034 -240.292785)
		(end 333.078836 -240.342928)
		(width 0.088646)
		(layer "In4.Cu")
		(net "M_C_CPU0_SB_DQS_DN<4>")
	)
	(arc
		(start 335.41335 -239.537494)
		(mid 335.136875 -239.604814)
		(end 334.862678 -239.528858)
		(width 0.088646)
		(layer "In4.Cu")
		(net "M_C_CPU0_SB_DQS_DN<4>")
	)
	(arc
		(start 340.90356 -239.644428)
		(mid 340.838014 -239.615934)
		(end 340.767416 -239.604804)
		(width 0.088646)
		(layer "In4.Cu")
		(net "M_C_CPU0_SB_DQS_DN<4>")
	)
	(arc
		(start 339.561678 -239.528858)
		(mid 339.37448 -239.478715)
		(end 339.187282 -239.528858)
		(width 0.088646)
		(layer "In4.Cu")
		(net "M_C_CPU0_SB_DQS_DN<4>")
	)
	(arc
		(start 334.862678 -239.528858)
		(mid 334.67548 -239.478715)
		(end 334.488282 -239.528858)
		(width 0.088646)
		(layer "In4.Cu")
		(net "M_C_CPU0_SB_DQS_DN<4>")
	)
	(arc
		(start 335.802478 -239.528858)
		(mid 335.61528 -239.478715)
		(end 335.428082 -239.528858)
		(width 0.088646)
		(layer "In4.Cu")
		(net "M_C_CPU0_SB_DQS_DN<4>")
	)
	(arc
		(start 338.237322 -239.534954)
		(mid 337.95889 -239.6048)
		(end 337.682078 -239.528858)
		(width 0.088646)
		(layer "In4.Cu")
		(net "M_C_CPU0_SB_DQS_DN<4>")
	)
	(arc
		(start 338.622132 -239.528858)
		(mid 338.434934 -239.478715)
		(end 338.247736 -239.528858)
		(width 0.088646)
		(layer "In4.Cu")
		(net "M_C_CPU0_SB_DQS_DN<4>")
	)
	(arc
		(start 340.501478 -239.528858)
		(mid 340.31428 -239.478715)
		(end 340.127082 -239.528858)
		(width 0.088646)
		(layer "In4.Cu")
		(net "M_C_CPU0_SB_DQS_DN<4>")
	)
	(arc
		(start 337.29295 -239.537494)
		(mid 337.016475 -239.604814)
		(end 336.742278 -239.528858)
		(width 0.088646)
		(layer "In4.Cu")
		(net "M_C_CPU0_SB_DQS_DN<4>")
	)
	(arc
		(start 336.35315 -239.537494)
		(mid 336.076675 -239.604814)
		(end 335.802478 -239.528858)
		(width 0.088646)
		(layer "In4.Cu")
		(net "M_C_CPU0_SB_DQS_DN<4>")
	)
	(arc
		(start 337.682078 -239.528858)
		(mid 337.49488 -239.478715)
		(end 337.307682 -239.528858)
		(width 0.088646)
		(layer "In4.Cu")
		(net "M_C_CPU0_SB_DQS_DN<4>")
	)
	(arc
		(start 334.30083 -239.875314)
		(mid 334.016399 -240.344215)
		(end 333.467964 -240.351564)
		(width 0.088646)
		(layer "In4.Cu")
		(net "M_C_CPU0_SB_DQS_DN<4>")
	)
	(segment
		(start 274.155408 -200.2917)
		(end 274.14474 -200.281032)
		(width 0.101854)
		(layer "F.Cu")
		(net "M_C_CPU0_SB_DQS_DN<3>")
	)
	(segment
		(start 273.127724 -200.553066)
		(end 272.491708 -200.12787)
		(width 0.20066)
		(layer "F.Cu")
		(net "M_C_CPU0_SB_DQS_DN<3>")
	)
	(segment
		(start 277.904194 -200.12787)
		(end 277.49754 -200.12787)
		(width 0.20066)
		(layer "F.Cu")
		(net "M_C_CPU0_SB_DQS_DN<3>")
	)
	(segment
		(start 277.072344 -200.553066)
		(end 276.885654 -200.553066)
		(width 0.20066)
		(layer "F.Cu")
		(net "M_C_CPU0_SB_DQS_DN<3>")
	)
	(segment
		(start 272.491708 -200.12787)
		(end 271.977866 -200.12787)
		(width 0.20066)
		(layer "F.Cu")
		(net "M_C_CPU0_SB_DQS_DN<3>")
	)
	(segment
		(start 278.711914 -199.866758)
		(end 278.165306 -199.866758)
		(width 0.20066)
		(layer "F.Cu")
		(net "M_C_CPU0_SB_DQS_DN<3>")
	)
	(segment
		(start 273.939762 -200.281032)
		(end 273.667728 -200.553066)
		(width 0.20066)
		(layer "F.Cu")
		(net "M_C_CPU0_SB_DQS_DN<3>")
	)
	(segment
		(start 342.664034 -228.180646)
		(end 342.664034 -227.64496)
		(width 0.20066)
		(layer "F.Cu")
		(net "M_C_CPU0_SB_DQS_DN<3>")
	)
	(segment
		(start 271.977866 -200.12787)
		(end 271.716754 -199.866758)
		(width 0.20066)
		(layer "F.Cu")
		(net "M_C_CPU0_SB_DQS_DN<3>")
	)
	(segment
		(start 271.716754 -199.866758)
		(end 271.168114 -199.866758)
		(width 0.20066)
		(layer "F.Cu")
		(net "M_C_CPU0_SB_DQS_DN<3>")
	)
	(segment
		(start 276.469094 -200.2917)
		(end 274.155408 -200.2917)
		(width 0.1016)
		(layer "F.Cu")
		(net "M_C_CPU0_SB_DQS_DN<3>")
	)
	(segment
		(start 279.816814 -199.866758)
		(end 278.711914 -199.866758)
		(width 0.20066)
		(layer "F.Cu")
		(net "M_C_CPU0_SB_DQS_DN<3>")
	)
	(segment
		(start 277.49754 -200.12787)
		(end 277.072344 -200.553066)
		(width 0.20066)
		(layer "F.Cu")
		(net "M_C_CPU0_SB_DQS_DN<3>")
	)
	(segment
		(start 276.624288 -200.2917)
		(end 276.469094 -200.2917)
		(width 0.20066)
		(layer "F.Cu")
		(net "M_C_CPU0_SB_DQS_DN<3>")
	)
	(segment
		(start 276.885654 -200.553066)
		(end 276.624288 -200.2917)
		(width 0.20066)
		(layer "F.Cu")
		(net "M_C_CPU0_SB_DQS_DN<3>")
	)
	(segment
		(start 274.143978 -200.281032)
		(end 273.939762 -200.281032)
		(width 0.20066)
		(layer "F.Cu")
		(net "M_C_CPU0_SB_DQS_DN<3>")
	)
	(segment
		(start 273.667728 -200.553066)
		(end 273.127724 -200.553066)
		(width 0.20066)
		(layer "F.Cu")
		(net "M_C_CPU0_SB_DQS_DN<3>")
	)
	(segment
		(start 274.14474 -200.281032)
		(end 274.143978 -200.281032)
		(width 0.101854)
		(layer "F.Cu")
		(net "M_C_CPU0_SB_DQS_DN<3>")
	)
	(segment
		(start 278.165306 -199.866758)
		(end 277.904194 -200.12787)
		(width 0.20066)
		(layer "F.Cu")
		(net "M_C_CPU0_SB_DQS_DN<3>")
	)
	(segment
		(start 342.66378 -228.1809)
		(end 342.664034 -228.180646)
		(width 0.20066)
		(layer "F.Cu")
		(net "M_C_CPU0_SB_DQS_DN<3>")
	)
	(segment
		(start 281.820112 -199.899016)
		(end 281.084782 -199.899016)
		(width 0.18288)
		(layer "In6.Cu")
		(net "M_C_CPU0_SB_DQS_DN<3>")
	)
	(segment
		(start 304.392838 -199.466454)
		(end 303.844198 -199.466454)
		(width 0.18288)
		(layer "In6.Cu")
		(net "M_C_CPU0_SB_DQS_DN<3>")
	)
	(segment
		(start 313.456828 -202.488038)
		(end 313.068716 -202.099672)
		(width 0.18288)
		(layer "In6.Cu")
		(net "M_C_CPU0_SB_DQS_DN<3>")
	)
	(segment
		(start 330.443078 -223.110044)
		(end 330.41971 -223.110044)
		(width 0.088646)
		(layer "In6.Cu")
		(net "M_C_CPU0_SB_DQS_DN<3>")
	)
	(segment
		(start 305.065938 -199.341994)
		(end 304.517298 -199.341994)
		(width 0.18288)
		(layer "In6.Cu")
		(net "M_C_CPU0_SB_DQS_DN<3>")
	)
	(segment
		(start 317.066676 -205.858364)
		(end 317.066676 -205.682342)
		(width 0.18288)
		(layer "In6.Cu")
		(net "M_C_CPU0_SB_DQS_DN<3>")
	)
	(segment
		(start 338.247482 -227.155502)
		(end 338.23275 -227.146866)
		(width 0.088646)
		(layer "In6.Cu")
		(net "M_C_CPU0_SB_DQS_DN<3>")
	)
	(segment
		(start 284.466538 -200.436226)
		(end 284.361382 -200.436226)
		(width 0.18288)
		(layer "In6.Cu")
		(net "M_C_CPU0_SB_DQS_DN<3>")
	)
	(segment
		(start 282.403296 -200.140316)
		(end 281.820112 -199.899016)
		(width 0.18288)
		(layer "In6.Cu")
		(net "M_C_CPU0_SB_DQS_DN<3>")
	)
	(segment
		(start 340.133432 -227.159058)
		(end 340.127336 -227.155502)
		(width 0.088646)
		(layer "In6.Cu")
		(net "M_C_CPU0_SB_DQS_DN<3>")
	)
	(segment
		(start 309.281322 -200.241408)
		(end 308.774084 -200.03135)
		(width 0.18288)
		(layer "In6.Cu")
		(net "M_C_CPU0_SB_DQS_DN<3>")
	)
	(segment
		(start 293.012368 -198.254366)
		(end 292.57752 -198.254366)
		(width 0.18288)
		(layer "In6.Cu")
		(net "M_C_CPU0_SB_DQS_DN<3>")
	)
	(segment
		(start 341.53729 -227.969318)
		(end 341.537036 -227.969318)
		(width 0.088646)
		(layer "In6.Cu")
		(net "M_C_CPU0_SB_DQS_DN<3>")
	)
	(segment
		(start 283.72943 -200.290938)
		(end 283.459682 -200.560686)
		(width 0.18288)
		(layer "In6.Cu")
		(net "M_C_CPU0_SB_DQS_DN<3>")
	)
	(segment
		(start 310.017922 -200.546716)
		(end 309.855362 -200.614026)
		(width 0.18288)
		(layer "In6.Cu")
		(net "M_C_CPU0_SB_DQS_DN<3>")
	)
	(segment
		(start 286.58185 -198.85406)
		(end 285.671514 -199.23125)
		(width 0.18288)
		(layer "In6.Cu")
		(net "M_C_CPU0_SB_DQS_DN<3>")
	)
	(segment
		(start 312.504836 -201.711814)
		(end 311.836308 -201.434954)
		(width 0.18288)
		(layer "In6.Cu")
		(net "M_C_CPU0_SB_DQS_DN<3>")
	)
	(segment
		(start 335.710784 -226.017328)
		(end 335.710784 -226.003104)
		(width 0.088646)
		(layer "In6.Cu")
		(net "M_C_CPU0_SB_DQS_DN<3>")
	)
	(segment
		(start 307.085238 -199.466454)
		(end 306.536598 -199.466454)
		(width 0.18288)
		(layer "In6.Cu")
		(net "M_C_CPU0_SB_DQS_DN<3>")
	)
	(segment
		(start 299.456348 -197.995286)
		(end 299.202094 -197.741032)
		(width 0.18288)
		(layer "In6.Cu")
		(net "M_C_CPU0_SB_DQS_DN<3>")
	)
	(segment
		(start 284.216094 -200.290938)
		(end 283.72943 -200.290938)
		(width 0.18288)
		(layer "In6.Cu")
		(net "M_C_CPU0_SB_DQS_DN<3>")
	)
	(segment
		(start 303.046638 -199.466454)
		(end 302.048164 -199.466454)
		(width 0.18288)
		(layer "In6.Cu")
		(net "M_C_CPU0_SB_DQS_DN<3>")
	)
	(segment
		(start 306.536598 -199.466454)
		(end 306.412138 -199.341994)
		(width 0.18288)
		(layer "In6.Cu")
		(net "M_C_CPU0_SB_DQS_DN<3>")
	)
	(segment
		(start 287.825434 -198.863966)
		(end 287.539938 -198.57847)
		(width 0.18288)
		(layer "In6.Cu")
		(net "M_C_CPU0_SB_DQS_DN<3>")
	)
	(segment
		(start 296.25036 -198.857108)
		(end 295.361868 -198.857108)
		(width 0.18288)
		(layer "In6.Cu")
		(net "M_C_CPU0_SB_DQS_DN<3>")
	)
	(segment
		(start 301.620428 -199.038972)
		(end 301.620174 -198.86295)
		(width 0.18288)
		(layer "In6.Cu")
		(net "M_C_CPU0_SB_DQS_DN<3>")
	)
	(segment
		(start 339.576664 -227.146866)
		(end 339.561932 -227.155502)
		(width 0.088646)
		(layer "In6.Cu")
		(net "M_C_CPU0_SB_DQS_DN<3>")
	)
	(segment
		(start 293.3319 -198.386446)
		(end 293.012368 -198.254366)
		(width 0.18288)
		(layer "In6.Cu")
		(net "M_C_CPU0_SB_DQS_DN<3>")
	)
	(segment
		(start 280.074878 -200.124822)
		(end 279.816814 -199.866758)
		(width 0.18288)
		(layer "In6.Cu")
		(net "M_C_CPU0_SB_DQS_DN<3>")
	)
	(segment
		(start 315.55055 -204.342238)
		(end 314.296806 -203.088494)
		(width 0.18288)
		(layer "In6.Cu")
		(net "M_C_CPU0_SB_DQS_DN<3>")
	)
	(segment
		(start 328.189336 -219.977208)
		(end 319.542414 -211.330286)
		(width 0.18288)
		(layer "In6.Cu")
		(net "M_C_CPU0_SB_DQS_DN<3>")
	)
	(segment
		(start 298.28109 -198.01586)
		(end 296.25036 -198.857108)
		(width 0.18288)
		(layer "In6.Cu")
		(net "M_C_CPU0_SB_DQS_DN<3>")
	)
	(segment
		(start 332.973426 -225.533458)
		(end 332.971394 -225.534474)
		(width 0.088646)
		(layer "In6.Cu")
		(net "M_C_CPU0_SB_DQS_DN<3>")
	)
	(segment
		(start 317.066676 -205.682342)
		(end 316.678564 -205.29423)
		(width 0.18288)
		(layer "In6.Cu")
		(net "M_C_CPU0_SB_DQS_DN<3>")
	)
	(segment
		(start 305.190398 -199.466454)
		(end 305.065938 -199.341994)
		(width 0.18288)
		(layer "In6.Cu")
		(net "M_C_CPU0_SB_DQS_DN<3>")
	)
	(segment
		(start 339.187536 -227.155502)
		(end 339.177122 -227.149406)
		(width 0.088646)
		(layer "In6.Cu")
		(net "M_C_CPU0_SB_DQS_DN<3>")
	)
	(segment
		(start 342.165178 -227.823776)
		(end 341.91194 -227.969572)
		(width 0.088646)
		(layer "In6.Cu")
		(net "M_C_CPU0_SB_DQS_DN<3>")
	)
	(segment
		(start 301.620174 -198.86295)
		(end 301.232062 -198.474838)
		(width 0.18288)
		(layer "In6.Cu")
		(net "M_C_CPU0_SB_DQS_DN<3>")
	)
	(segment
		(start 293.567612 -198.622412)
		(end 293.3319 -198.386446)
		(width 0.18288)
		(layer "In6.Cu")
		(net "M_C_CPU0_SB_DQS_DN<3>")
	)
	(segment
		(start 293.803324 -198.858124)
		(end 293.567612 -198.622412)
		(width 0.18288)
		(layer "In6.Cu")
		(net "M_C_CPU0_SB_DQS_DN<3>")
	)
	(segment
		(start 285.671514 -199.23125)
		(end 284.466538 -200.436226)
		(width 0.18288)
		(layer "In6.Cu")
		(net "M_C_CPU0_SB_DQS_DN<3>")
	)
	(segment
		(start 334.877664 -225.51898)
		(end 334.862932 -225.527616)
		(width 0.088646)
		(layer "In6.Cu")
		(net "M_C_CPU0_SB_DQS_DN<3>")
	)
	(segment
		(start 311.836308 -201.434954)
		(end 311.768744 -201.271886)
		(width 0.18288)
		(layer "In6.Cu")
		(net "M_C_CPU0_SB_DQS_DN<3>")
	)
	(segment
		(start 342.664034 -227.64496)
		(end 342.632284 -227.760784)
		(width 0.088646)
		(layer "In6.Cu")
		(net "M_C_CPU0_SB_DQS_DN<3>")
	)
	(segment
		(start 313.068716 -202.099672)
		(end 312.892694 -202.099672)
		(width 0.18288)
		(layer "In6.Cu")
		(net "M_C_CPU0_SB_DQS_DN<3>")
	)
	(segment
		(start 308.774084 -200.03135)
		(end 308.611524 -200.09866)
		(width 0.18288)
		(layer "In6.Cu")
		(net "M_C_CPU0_SB_DQS_DN<3>")
	)
	(segment
		(start 290.417758 -199.149208)
		(end 288.840164 -199.149208)
		(width 0.18288)
		(layer "In6.Cu")
		(net "M_C_CPU0_SB_DQS_DN<3>")
	)
	(segment
		(start 332.53045 -225.468434)
		(end 331.190346 -224.12833)
		(width 0.088646)
		(layer "In6.Cu")
		(net "M_C_CPU0_SB_DQS_DN<3>")
	)
	(segment
		(start 303.844198 -199.466454)
		(end 303.719738 -199.341994)
		(width 0.18288)
		(layer "In6.Cu")
		(net "M_C_CPU0_SB_DQS_DN<3>")
	)
	(segment
		(start 303.171098 -199.341994)
		(end 303.046638 -199.466454)
		(width 0.18288)
		(layer "In6.Cu")
		(net "M_C_CPU0_SB_DQS_DN<3>")
	)
	(segment
		(start 311.26176 -201.062082)
		(end 311.0992 -201.129392)
		(width 0.18288)
		(layer "In6.Cu")
		(net "M_C_CPU0_SB_DQS_DN<3>")
	)
	(segment
		(start 305.739038 -199.466454)
		(end 305.190398 -199.466454)
		(width 0.18288)
		(layer "In6.Cu")
		(net "M_C_CPU0_SB_DQS_DN<3>")
	)
	(segment
		(start 300.57598 -197.995286)
		(end 299.456348 -197.995286)
		(width 0.18288)
		(layer "In6.Cu")
		(net "M_C_CPU0_SB_DQS_DN<3>")
	)
	(segment
		(start 303.719738 -199.341994)
		(end 303.171098 -199.341994)
		(width 0.18288)
		(layer "In6.Cu")
		(net "M_C_CPU0_SB_DQS_DN<3>")
	)
	(segment
		(start 298.525946 -198.01586)
		(end 298.28109 -198.01586)
		(width 0.18288)
		(layer "In6.Cu")
		(net "M_C_CPU0_SB_DQS_DN<3>")
	)
	(segment
		(start 294.708326 -198.590916)
		(end 294.441118 -198.858124)
		(width 0.18288)
		(layer "In6.Cu")
		(net "M_C_CPU0_SB_DQS_DN<3>")
	)
	(segment
		(start 312.892694 -202.099672)
		(end 312.504836 -201.711814)
		(width 0.18288)
		(layer "In6.Cu")
		(net "M_C_CPU0_SB_DQS_DN<3>")
	)
	(segment
		(start 336.180684 -226.83978)
		(end 336.180684 -226.821238)
		(width 0.088646)
		(layer "In6.Cu")
		(net "M_C_CPU0_SB_DQS_DN<3>")
	)
	(segment
		(start 302.048164 -199.466454)
		(end 301.620428 -199.038972)
		(width 0.18288)
		(layer "In6.Cu")
		(net "M_C_CPU0_SB_DQS_DN<3>")
	)
	(segment
		(start 287.177988 -198.57847)
		(end 286.902398 -198.85406)
		(width 0.18288)
		(layer "In6.Cu")
		(net "M_C_CPU0_SB_DQS_DN<3>")
	)
	(segment
		(start 283.459682 -200.560686)
		(end 282.823666 -200.560686)
		(width 0.18288)
		(layer "In6.Cu")
		(net "M_C_CPU0_SB_DQS_DN<3>")
	)
	(segment
		(start 328.672698 -223.110044)
		(end 328.189336 -222.626682)
		(width 0.18288)
		(layer "In6.Cu")
		(net "M_C_CPU0_SB_DQS_DN<3>")
	)
	(segment
		(start 311.0992 -201.129392)
		(end 310.59247 -200.919588)
		(width 0.18288)
		(layer "In6.Cu")
		(net "M_C_CPU0_SB_DQS_DN<3>")
	)
	(segment
		(start 306.412138 -199.341994)
		(end 305.863498 -199.341994)
		(width 0.18288)
		(layer "In6.Cu")
		(net "M_C_CPU0_SB_DQS_DN<3>")
	)
	(segment
		(start 341.91194 -227.969572)
		(end 341.911686 -227.969318)
		(width 0.088646)
		(layer "In6.Cu")
		(net "M_C_CPU0_SB_DQS_DN<3>")
	)
	(segment
		(start 335.898236 -226.341686)
		(end 335.889346 -226.336606)
		(width 0.088646)
		(layer "In6.Cu")
		(net "M_C_CPU0_SB_DQS_DN<3>")
	)
	(segment
		(start 310.59247 -200.919588)
		(end 310.52516 -200.756774)
		(width 0.18288)
		(layer "In6.Cu")
		(net "M_C_CPU0_SB_DQS_DN<3>")
	)
	(segment
		(start 309.348632 -200.404222)
		(end 309.281322 -200.241408)
		(width 0.18288)
		(layer "In6.Cu")
		(net "M_C_CPU0_SB_DQS_DN<3>")
	)
	(segment
		(start 295.095676 -198.590916)
		(end 294.708326 -198.590916)
		(width 0.18288)
		(layer "In6.Cu")
		(net "M_C_CPU0_SB_DQS_DN<3>")
	)
	(segment
		(start 282.823666 -200.560686)
		(end 282.403296 -200.140316)
		(width 0.18288)
		(layer "In6.Cu")
		(net "M_C_CPU0_SB_DQS_DN<3>")
	)
	(segment
		(start 319.542414 -211.330286)
		(end 317.454534 -206.246222)
		(width 0.18288)
		(layer "In6.Cu")
		(net "M_C_CPU0_SB_DQS_DN<3>")
	)
	(segment
		(start 313.456828 -202.66406)
		(end 313.456828 -202.488038)
		(width 0.18288)
		(layer "In6.Cu")
		(net "M_C_CPU0_SB_DQS_DN<3>")
	)
	(segment
		(start 316.678564 -205.29423)
		(end 316.502542 -205.29423)
		(width 0.18288)
		(layer "In6.Cu")
		(net "M_C_CPU0_SB_DQS_DN<3>")
	)
	(segment
		(start 331.190346 -224.12833)
		(end 331.190346 -223.48063)
		(width 0.088646)
		(layer "In6.Cu")
		(net "M_C_CPU0_SB_DQS_DN<3>")
	)
	(segment
		(start 311.768744 -201.271886)
		(end 311.26176 -201.062082)
		(width 0.18288)
		(layer "In6.Cu")
		(net "M_C_CPU0_SB_DQS_DN<3>")
	)
	(segment
		(start 301.05604 -198.474838)
		(end 300.57598 -197.995286)
		(width 0.18288)
		(layer "In6.Cu")
		(net "M_C_CPU0_SB_DQS_DN<3>")
	)
	(segment
		(start 287.539938 -198.57847)
		(end 287.177988 -198.57847)
		(width 0.18288)
		(layer "In6.Cu")
		(net "M_C_CPU0_SB_DQS_DN<3>")
	)
	(segment
		(start 315.726572 -204.342238)
		(end 315.55055 -204.342238)
		(width 0.18288)
		(layer "In6.Cu")
		(net "M_C_CPU0_SB_DQS_DN<3>")
	)
	(segment
		(start 317.454534 -206.246222)
		(end 317.066676 -205.858364)
		(width 0.18288)
		(layer "In6.Cu")
		(net "M_C_CPU0_SB_DQS_DN<3>")
	)
	(segment
		(start 301.232062 -198.474838)
		(end 301.05604 -198.474838)
		(width 0.18288)
		(layer "In6.Cu")
		(net "M_C_CPU0_SB_DQS_DN<3>")
	)
	(segment
		(start 305.863498 -199.341994)
		(end 305.739038 -199.466454)
		(width 0.18288)
		(layer "In6.Cu")
		(net "M_C_CPU0_SB_DQS_DN<3>")
	)
	(segment
		(start 340.597236 -227.969318)
		(end 340.588346 -227.964238)
		(width 0.088646)
		(layer "In6.Cu")
		(net "M_C_CPU0_SB_DQS_DN<3>")
	)
	(segment
		(start 342.632284 -227.760784)
		(end 342.593422 -227.782882)
		(width 0.088646)
		(layer "In6.Cu")
		(net "M_C_CPU0_SB_DQS_DN<3>")
	)
	(segment
		(start 330.41971 -223.110044)
		(end 328.672698 -223.110044)
		(width 0.18288)
		(layer "In6.Cu")
		(net "M_C_CPU0_SB_DQS_DN<3>")
	)
	(segment
		(start 310.52516 -200.756774)
		(end 310.017922 -200.546716)
		(width 0.18288)
		(layer "In6.Cu")
		(net "M_C_CPU0_SB_DQS_DN<3>")
	)
	(segment
		(start 284.361382 -200.436226)
		(end 284.216094 -200.290938)
		(width 0.18288)
		(layer "In6.Cu")
		(net "M_C_CPU0_SB_DQS_DN<3>")
	)
	(segment
		(start 281.084782 -199.899016)
		(end 280.539698 -200.124822)
		(width 0.18288)
		(layer "In6.Cu")
		(net "M_C_CPU0_SB_DQS_DN<3>")
	)
	(segment
		(start 316.114684 -204.73035)
		(end 315.726572 -204.342238)
		(width 0.18288)
		(layer "In6.Cu")
		(net "M_C_CPU0_SB_DQS_DN<3>")
	)
	(segment
		(start 294.441118 -198.858124)
		(end 293.803324 -198.858124)
		(width 0.18288)
		(layer "In6.Cu")
		(net "M_C_CPU0_SB_DQS_DN<3>")
	)
	(segment
		(start 313.881262 -203.088494)
		(end 313.456828 -202.66406)
		(width 0.18288)
		(layer "In6.Cu")
		(net "M_C_CPU0_SB_DQS_DN<3>")
	)
	(segment
		(start 332.998064 -225.51898)
		(end 332.973426 -225.533458)
		(width 0.088646)
		(layer "In6.Cu")
		(net "M_C_CPU0_SB_DQS_DN<3>")
	)
	(segment
		(start 304.517298 -199.341994)
		(end 304.392838 -199.466454)
		(width 0.18288)
		(layer "In6.Cu")
		(net "M_C_CPU0_SB_DQS_DN<3>")
	)
	(segment
		(start 292.57752 -198.254366)
		(end 290.417758 -199.149208)
		(width 0.18288)
		(layer "In6.Cu")
		(net "M_C_CPU0_SB_DQS_DN<3>")
	)
	(segment
		(start 342.438736 -227.823776)
		(end 342.165178 -227.823776)
		(width 0.088646)
		(layer "In6.Cu")
		(net "M_C_CPU0_SB_DQS_DN<3>")
	)
	(segment
		(start 314.296806 -203.088494)
		(end 313.881262 -203.088494)
		(width 0.18288)
		(layer "In6.Cu")
		(net "M_C_CPU0_SB_DQS_DN<3>")
	)
	(segment
		(start 286.902398 -198.85406)
		(end 286.58185 -198.85406)
		(width 0.18288)
		(layer "In6.Cu")
		(net "M_C_CPU0_SB_DQS_DN<3>")
	)
	(segment
		(start 299.202094 -197.741032)
		(end 298.800774 -197.741032)
		(width 0.18288)
		(layer "In6.Cu")
		(net "M_C_CPU0_SB_DQS_DN<3>")
	)
	(segment
		(start 308.611524 -200.09866)
		(end 307.085238 -199.466454)
		(width 0.18288)
		(layer "In6.Cu")
		(net "M_C_CPU0_SB_DQS_DN<3>")
	)
	(segment
		(start 316.502542 -205.29423)
		(end 316.114684 -204.906372)
		(width 0.18288)
		(layer "In6.Cu")
		(net "M_C_CPU0_SB_DQS_DN<3>")
	)
	(segment
		(start 328.189336 -222.626682)
		(end 328.189336 -219.977208)
		(width 0.18288)
		(layer "In6.Cu")
		(net "M_C_CPU0_SB_DQS_DN<3>")
	)
	(segment
		(start 309.855362 -200.614026)
		(end 309.348632 -200.404222)
		(width 0.18288)
		(layer "In6.Cu")
		(net "M_C_CPU0_SB_DQS_DN<3>")
	)
	(segment
		(start 288.840164 -199.149208)
		(end 288.151316 -198.863966)
		(width 0.18288)
		(layer "In6.Cu")
		(net "M_C_CPU0_SB_DQS_DN<3>")
	)
	(segment
		(start 316.114684 -204.906372)
		(end 316.114684 -204.73035)
		(width 0.18288)
		(layer "In6.Cu")
		(net "M_C_CPU0_SB_DQS_DN<3>")
	)
	(segment
		(start 331.190346 -223.48063)
		(end 330.87945 -223.169734)
		(width 0.088646)
		(layer "In6.Cu")
		(net "M_C_CPU0_SB_DQS_DN<3>")
	)
	(segment
		(start 337.307682 -227.155502)
		(end 337.29295 -227.146866)
		(width 0.088646)
		(layer "In6.Cu")
		(net "M_C_CPU0_SB_DQS_DN<3>")
	)
	(segment
		(start 280.539698 -200.124822)
		(end 280.074878 -200.124822)
		(width 0.18288)
		(layer "In6.Cu")
		(net "M_C_CPU0_SB_DQS_DN<3>")
	)
	(segment
		(start 288.151316 -198.863966)
		(end 287.825434 -198.863966)
		(width 0.18288)
		(layer "In6.Cu")
		(net "M_C_CPU0_SB_DQS_DN<3>")
	)
	(segment
		(start 298.800774 -197.741032)
		(end 298.525946 -198.01586)
		(width 0.18288)
		(layer "In6.Cu")
		(net "M_C_CPU0_SB_DQS_DN<3>")
	)
	(segment
		(start 295.361868 -198.857108)
		(end 295.095676 -198.590916)
		(width 0.18288)
		(layer "In6.Cu")
		(net "M_C_CPU0_SB_DQS_DN<3>")
	)
	(segment
		(start 330.502768 -223.169734)
		(end 330.443078 -223.110044)
		(width 0.088646)
		(layer "In6.Cu")
		(net "M_C_CPU0_SB_DQS_DN<3>")
	)
	(segment
		(start 330.87945 -223.169734)
		(end 330.502768 -223.169734)
		(width 0.088646)
		(layer "In6.Cu")
		(net "M_C_CPU0_SB_DQS_DN<3>")
	)
	(segment
		(start 340.986364 -227.960682)
		(end 340.971632 -227.969318)
		(width 0.088646)
		(layer "In6.Cu")
		(net "M_C_CPU0_SB_DQS_DN<3>")
	)
	(arc
		(start 333.548736 -225.527616)
		(mid 333.274507 -225.451691)
		(end 332.998064 -225.51898)
		(width 0.088646)
		(layer "In6.Cu")
		(net "M_C_CPU0_SB_DQS_DN<3>")
	)
	(arc
		(start 335.889346 -226.336606)
		(mid 335.758432 -226.200246)
		(end 335.710784 -226.017328)
		(width 0.088646)
		(layer "In6.Cu")
		(net "M_C_CPU0_SB_DQS_DN<3>")
	)
	(arc
		(start 336.742278 -227.155502)
		(mid 336.55508 -227.205645)
		(end 336.367882 -227.155502)
		(width 0.088646)
		(layer "In6.Cu")
		(net "M_C_CPU0_SB_DQS_DN<3>")
	)
	(arc
		(start 332.608428 -225.527616)
		(mid 332.601653 -225.523625)
		(end 332.594966 -225.519488)
		(width 0.088646)
		(layer "In6.Cu")
		(net "M_C_CPU0_SB_DQS_DN<3>")
	)
	(arc
		(start 335.710784 -226.003104)
		(mid 335.631643 -225.728481)
		(end 335.428336 -225.527616)
		(width 0.088646)
		(layer "In6.Cu")
		(net "M_C_CPU0_SB_DQS_DN<3>")
	)
	(arc
		(start 335.428336 -225.527616)
		(mid 335.154107 -225.451691)
		(end 334.877664 -225.51898)
		(width 0.088646)
		(layer "In6.Cu")
		(net "M_C_CPU0_SB_DQS_DN<3>")
	)
	(arc
		(start 342.593422 -227.782882)
		(mid 342.518737 -227.813387)
		(end 342.438736 -227.823776)
		(width 0.088646)
		(layer "In6.Cu")
		(net "M_C_CPU0_SB_DQS_DN<3>")
	)
	(arc
		(start 341.537036 -227.969318)
		(mid 341.262807 -227.893393)
		(end 340.986364 -227.960682)
		(width 0.088646)
		(layer "In6.Cu")
		(net "M_C_CPU0_SB_DQS_DN<3>")
	)
	(arc
		(start 339.561932 -227.155502)
		(mid 339.374734 -227.205645)
		(end 339.187536 -227.155502)
		(width 0.088646)
		(layer "In6.Cu")
		(net "M_C_CPU0_SB_DQS_DN<3>")
	)
	(arc
		(start 340.588346 -227.964238)
		(mid 340.457432 -227.827878)
		(end 340.409784 -227.64496)
		(width 0.088646)
		(layer "In6.Cu")
		(net "M_C_CPU0_SB_DQS_DN<3>")
	)
	(arc
		(start 340.127336 -227.155502)
		(mid 339.853137 -227.079667)
		(end 339.576664 -227.146866)
		(width 0.088646)
		(layer "In6.Cu")
		(net "M_C_CPU0_SB_DQS_DN<3>")
	)
	(arc
		(start 334.488536 -225.527616)
		(mid 334.205834 -225.451874)
		(end 333.923132 -225.527616)
		(width 0.088646)
		(layer "In6.Cu")
		(net "M_C_CPU0_SB_DQS_DN<3>")
	)
	(arc
		(start 341.911686 -227.969318)
		(mid 341.724488 -228.019461)
		(end 341.53729 -227.969318)
		(width 0.088646)
		(layer "In6.Cu")
		(net "M_C_CPU0_SB_DQS_DN<3>")
	)
	(arc
		(start 337.682078 -227.155502)
		(mid 337.49488 -227.205645)
		(end 337.307682 -227.155502)
		(width 0.088646)
		(layer "In6.Cu")
		(net "M_C_CPU0_SB_DQS_DN<3>")
	)
	(arc
		(start 332.971394 -225.534474)
		(mid 332.789029 -225.577917)
		(end 332.608428 -225.527616)
		(width 0.088646)
		(layer "In6.Cu")
		(net "M_C_CPU0_SB_DQS_DN<3>")
	)
	(arc
		(start 336.180684 -226.821238)
		(mid 336.102573 -226.544289)
		(end 335.898236 -226.341686)
		(width 0.088646)
		(layer "In6.Cu")
		(net "M_C_CPU0_SB_DQS_DN<3>")
	)
	(arc
		(start 340.971632 -227.969318)
		(mid 340.784434 -228.019461)
		(end 340.597236 -227.969318)
		(width 0.088646)
		(layer "In6.Cu")
		(net "M_C_CPU0_SB_DQS_DN<3>")
	)
	(arc
		(start 338.23275 -227.146866)
		(mid 337.956275 -227.079546)
		(end 337.682078 -227.155502)
		(width 0.088646)
		(layer "In6.Cu")
		(net "M_C_CPU0_SB_DQS_DN<3>")
	)
	(arc
		(start 339.177122 -227.149406)
		(mid 338.89869 -227.07956)
		(end 338.621878 -227.155502)
		(width 0.088646)
		(layer "In6.Cu")
		(net "M_C_CPU0_SB_DQS_DN<3>")
	)
	(arc
		(start 340.409784 -227.64496)
		(mid 340.335868 -227.365458)
		(end 340.133432 -227.159058)
		(width 0.088646)
		(layer "In6.Cu")
		(net "M_C_CPU0_SB_DQS_DN<3>")
	)
	(arc
		(start 334.862932 -225.527616)
		(mid 334.675734 -225.577759)
		(end 334.488536 -225.527616)
		(width 0.088646)
		(layer "In6.Cu")
		(net "M_C_CPU0_SB_DQS_DN<3>")
	)
	(arc
		(start 336.367882 -227.155502)
		(mid 336.232949 -227.022148)
		(end 336.180684 -226.83978)
		(width 0.088646)
		(layer "In6.Cu")
		(net "M_C_CPU0_SB_DQS_DN<3>")
	)
	(arc
		(start 332.594966 -225.519488)
		(mid 332.561301 -225.495738)
		(end 332.53045 -225.468434)
		(width 0.088646)
		(layer "In6.Cu")
		(net "M_C_CPU0_SB_DQS_DN<3>")
	)
	(arc
		(start 337.29295 -227.146866)
		(mid 337.016475 -227.079546)
		(end 336.742278 -227.155502)
		(width 0.088646)
		(layer "In6.Cu")
		(net "M_C_CPU0_SB_DQS_DN<3>")
	)
	(arc
		(start 338.621878 -227.155502)
		(mid 338.43468 -227.205645)
		(end 338.247482 -227.155502)
		(width 0.088646)
		(layer "In6.Cu")
		(net "M_C_CPU0_SB_DQS_DN<3>")
	)
	(arc
		(start 333.923132 -225.527616)
		(mid 333.735934 -225.577759)
		(end 333.548736 -225.527616)
		(width 0.088646)
		(layer "In6.Cu")
		(net "M_C_CPU0_SB_DQS_DN<3>")
	)
	(segment
		(start 279.816814 -209.216752)
		(end 278.711914 -209.216752)
		(width 0.20066)
		(layer "F.Cu")
		(net "M_C_CPU0_SB_DQS_DN<2>")
	)
	(segment
		(start 274.155408 -209.641694)
		(end 274.14474 -209.631026)
		(width 0.101854)
		(layer "F.Cu")
		(net "M_C_CPU0_SB_DQS_DN<2>")
	)
	(segment
		(start 277.904194 -209.477864)
		(end 277.49754 -209.477864)
		(width 0.20066)
		(layer "F.Cu")
		(net "M_C_CPU0_SB_DQS_DN<2>")
	)
	(segment
		(start 272.491708 -209.477864)
		(end 271.977866 -209.477864)
		(width 0.20066)
		(layer "F.Cu")
		(net "M_C_CPU0_SB_DQS_DN<2>")
	)
	(segment
		(start 276.469094 -209.641694)
		(end 274.155408 -209.641694)
		(width 0.1016)
		(layer "F.Cu")
		(net "M_C_CPU0_SB_DQS_DN<2>")
	)
	(segment
		(start 339.37448 -230.622348)
		(end 339.37448 -230.086662)
		(width 0.20066)
		(layer "F.Cu")
		(net "M_C_CPU0_SB_DQS_DN<2>")
	)
	(segment
		(start 278.711914 -209.216752)
		(end 278.165306 -209.216752)
		(width 0.20066)
		(layer "F.Cu")
		(net "M_C_CPU0_SB_DQS_DN<2>")
	)
	(segment
		(start 274.14474 -209.631026)
		(end 274.143978 -209.631026)
		(width 0.101854)
		(layer "F.Cu")
		(net "M_C_CPU0_SB_DQS_DN<2>")
	)
	(segment
		(start 271.716754 -209.216752)
		(end 271.168114 -209.216752)
		(width 0.20066)
		(layer "F.Cu")
		(net "M_C_CPU0_SB_DQS_DN<2>")
	)
	(segment
		(start 276.885654 -209.90306)
		(end 276.624288 -209.641694)
		(width 0.20066)
		(layer "F.Cu")
		(net "M_C_CPU0_SB_DQS_DN<2>")
	)
	(segment
		(start 276.624288 -209.641694)
		(end 276.469094 -209.641694)
		(width 0.20066)
		(layer "F.Cu")
		(net "M_C_CPU0_SB_DQS_DN<2>")
	)
	(segment
		(start 277.49754 -209.477864)
		(end 277.072344 -209.90306)
		(width 0.20066)
		(layer "F.Cu")
		(net "M_C_CPU0_SB_DQS_DN<2>")
	)
	(segment
		(start 274.143978 -209.631026)
		(end 273.939762 -209.631026)
		(width 0.20066)
		(layer "F.Cu")
		(net "M_C_CPU0_SB_DQS_DN<2>")
	)
	(segment
		(start 273.127724 -209.90306)
		(end 272.491708 -209.477864)
		(width 0.20066)
		(layer "F.Cu")
		(net "M_C_CPU0_SB_DQS_DN<2>")
	)
	(segment
		(start 271.977866 -209.477864)
		(end 271.716754 -209.216752)
		(width 0.20066)
		(layer "F.Cu")
		(net "M_C_CPU0_SB_DQS_DN<2>")
	)
	(segment
		(start 278.165306 -209.216752)
		(end 277.904194 -209.477864)
		(width 0.20066)
		(layer "F.Cu")
		(net "M_C_CPU0_SB_DQS_DN<2>")
	)
	(segment
		(start 273.939762 -209.631026)
		(end 273.667728 -209.90306)
		(width 0.20066)
		(layer "F.Cu")
		(net "M_C_CPU0_SB_DQS_DN<2>")
	)
	(segment
		(start 273.667728 -209.90306)
		(end 273.127724 -209.90306)
		(width 0.20066)
		(layer "F.Cu")
		(net "M_C_CPU0_SB_DQS_DN<2>")
	)
	(segment
		(start 277.072344 -209.90306)
		(end 276.885654 -209.90306)
		(width 0.20066)
		(layer "F.Cu")
		(net "M_C_CPU0_SB_DQS_DN<2>")
	)
	(segment
		(start 339.374734 -230.622602)
		(end 339.37448 -230.622348)
		(width 0.20066)
		(layer "F.Cu")
		(net "M_C_CPU0_SB_DQS_DN<2>")
	)
	(segment
		(start 339.273896 -230.228394)
		(end 339.132672 -230.265478)
		(width 0.088646)
		(layer "In4.Cu")
		(net "M_C_CPU0_SB_DQS_DN<2>")
	)
	(segment
		(start 336.748374 -230.407718)
		(end 336.744056 -230.410258)
		(width 0.088646)
		(layer "In4.Cu")
		(net "M_C_CPU0_SB_DQS_DN<2>")
	)
	(segment
		(start 293.12235 -211.685632)
		(end 292.503352 -211.685632)
		(width 0.18288)
		(layer "In4.Cu")
		(net "M_C_CPU0_SB_DQS_DN<2>")
	)
	(segment
		(start 333.548482 -230.41102)
		(end 333.53375 -230.402384)
		(width 0.088646)
		(layer "In4.Cu")
		(net "M_C_CPU0_SB_DQS_DN<2>")
	)
	(segment
		(start 336.744056 -230.410258)
		(end 336.742532 -230.41102)
		(width 0.088646)
		(layer "In4.Cu")
		(net "M_C_CPU0_SB_DQS_DN<2>")
	)
	(segment
		(start 312.976768 -212.34527)
		(end 312.852308 -212.46973)
		(width 0.18288)
		(layer "In4.Cu")
		(net "M_C_CPU0_SB_DQS_DN<2>")
	)
	(segment
		(start 302.839882 -211.624164)
		(end 299.460412 -211.624164)
		(width 0.18288)
		(layer "In4.Cu")
		(net "M_C_CPU0_SB_DQS_DN<2>")
	)
	(segment
		(start 317.323724 -218.569794)
		(end 317.16091 -218.502484)
		(width 0.18288)
		(layer "In4.Cu")
		(net "M_C_CPU0_SB_DQS_DN<2>")
	)
	(segment
		(start 315.614558 -214.77097)
		(end 315.404754 -214.26424)
		(width 0.18288)
		(layer "In4.Cu")
		(net "M_C_CPU0_SB_DQS_DN<2>")
	)
	(segment
		(start 317.982092 -220.48343)
		(end 318.049402 -220.32087)
		(width 0.18288)
		(layer "In4.Cu")
		(net "M_C_CPU0_SB_DQS_DN<2>")
	)
	(segment
		(start 314.452508 -212.46973)
		(end 313.649868 -212.46973)
		(width 0.18288)
		(layer "In4.Cu")
		(net "M_C_CPU0_SB_DQS_DN<2>")
	)
	(segment
		(start 339.37448 -230.086662)
		(end 339.358478 -230.144574)
		(width 0.088646)
		(layer "In4.Cu")
		(net "M_C_CPU0_SB_DQS_DN<2>")
	)
	(segment
		(start 312.852308 -212.46973)
		(end 312.109866 -212.46973)
		(width 0.18288)
		(layer "In4.Cu")
		(net "M_C_CPU0_SB_DQS_DN<2>")
	)
	(segment
		(start 338.247736 -230.41102)
		(end 338.237322 -230.404924)
		(width 0.088646)
		(layer "In4.Cu")
		(net "M_C_CPU0_SB_DQS_DN<2>")
	)
	(segment
		(start 295.093136 -212.191854)
		(end 294.710358 -212.191854)
		(width 0.18288)
		(layer "In4.Cu")
		(net "M_C_CPU0_SB_DQS_DN<2>")
	)
	(segment
		(start 283.719778 -209.641694)
		(end 283.454856 -209.906616)
		(width 0.18288)
		(layer "In4.Cu")
		(net "M_C_CPU0_SB_DQS_DN<2>")
	)
	(segment
		(start 330.731622 -229.233476)
		(end 330.671932 -229.173786)
		(width 0.088646)
		(layer "In4.Cu")
		(net "M_C_CPU0_SB_DQS_DN<2>")
	)
	(segment
		(start 303.613058 -210.850988)
		(end 302.839882 -211.624164)
		(width 0.18288)
		(layer "In4.Cu")
		(net "M_C_CPU0_SB_DQS_DN<2>")
	)
	(segment
		(start 330.648564 -229.173786)
		(end 325.646796 -229.173786)
		(width 0.18288)
		(layer "In4.Cu")
		(net "M_C_CPU0_SB_DQS_DN<2>")
	)
	(segment
		(start 293.892986 -212.456268)
		(end 293.12235 -211.685632)
		(width 0.18288)
		(layer "In4.Cu")
		(net "M_C_CPU0_SB_DQS_DN<2>")
	)
	(segment
		(start 332.608682 -230.41102)
		(end 332.601316 -230.406702)
		(width 0.088646)
		(layer "In4.Cu")
		(net "M_C_CPU0_SB_DQS_DN<2>")
	)
	(segment
		(start 306.944776 -210.850988)
		(end 303.613058 -210.850988)
		(width 0.18288)
		(layer "In4.Cu")
		(net "M_C_CPU0_SB_DQS_DN<2>")
	)
	(segment
		(start 291.59327 -210.77555)
		(end 288.545524 -210.77555)
		(width 0.18288)
		(layer "In4.Cu")
		(net "M_C_CPU0_SB_DQS_DN<2>")
	)
	(segment
		(start 318.191896 -220.99016)
		(end 317.982092 -220.48343)
		(width 0.18288)
		(layer "In4.Cu")
		(net "M_C_CPU0_SB_DQS_DN<2>")
	)
	(segment
		(start 318.497458 -221.727268)
		(end 318.564768 -221.564708)
		(width 0.18288)
		(layer "In4.Cu")
		(net "M_C_CPU0_SB_DQS_DN<2>")
	)
	(segment
		(start 284.174184 -209.641694)
		(end 283.719778 -209.641694)
		(width 0.18288)
		(layer "In4.Cu")
		(net "M_C_CPU0_SB_DQS_DN<2>")
	)
	(segment
		(start 294.445944 -212.456268)
		(end 293.892986 -212.456268)
		(width 0.18288)
		(layer "In4.Cu")
		(net "M_C_CPU0_SB_DQS_DN<2>")
	)
	(segment
		(start 312.109866 -212.46973)
		(end 309.971186 -211.584032)
		(width 0.18288)
		(layer "In4.Cu")
		(net "M_C_CPU0_SB_DQS_DN<2>")
	)
	(segment
		(start 284.450536 -209.918046)
		(end 284.174184 -209.641694)
		(width 0.18288)
		(layer "In4.Cu")
		(net "M_C_CPU0_SB_DQS_DN<2>")
	)
	(segment
		(start 313.649868 -212.46973)
		(end 313.525408 -212.34527)
		(width 0.18288)
		(layer "In4.Cu")
		(net "M_C_CPU0_SB_DQS_DN<2>")
	)
	(segment
		(start 315.098938 -213.527132)
		(end 314.808362 -212.825584)
		(width 0.18288)
		(layer "In4.Cu")
		(net "M_C_CPU0_SB_DQS_DN<2>")
	)
	(segment
		(start 318.564768 -221.564708)
		(end 318.35471 -221.05747)
		(width 0.18288)
		(layer "In4.Cu")
		(net "M_C_CPU0_SB_DQS_DN<2>")
	)
	(segment
		(start 316.645544 -217.258646)
		(end 316.43574 -216.751916)
		(width 0.18288)
		(layer "In4.Cu")
		(net "M_C_CPU0_SB_DQS_DN<2>")
	)
	(segment
		(start 309.971186 -211.584032)
		(end 307.67782 -211.584032)
		(width 0.18288)
		(layer "In4.Cu")
		(net "M_C_CPU0_SB_DQS_DN<2>")
	)
	(segment
		(start 331.524356 -229.673912)
		(end 331.08392 -229.233476)
		(width 0.088646)
		(layer "In4.Cu")
		(net "M_C_CPU0_SB_DQS_DN<2>")
	)
	(segment
		(start 336.742532 -230.41102)
		(end 336.738722 -230.413306)
		(width 0.088646)
		(layer "In4.Cu")
		(net "M_C_CPU0_SB_DQS_DN<2>")
	)
	(segment
		(start 294.710358 -212.191854)
		(end 294.445944 -212.456268)
		(width 0.18288)
		(layer "In4.Cu")
		(net "M_C_CPU0_SB_DQS_DN<2>")
	)
	(segment
		(start 315.472064 -214.10168)
		(end 315.262006 -213.594442)
		(width 0.18288)
		(layer "In4.Cu")
		(net "M_C_CPU0_SB_DQS_DN<2>")
	)
	(segment
		(start 297.257978 -212.46465)
		(end 295.365932 -212.46465)
		(width 0.18288)
		(layer "In4.Cu")
		(net "M_C_CPU0_SB_DQS_DN<2>")
	)
	(segment
		(start 299.177964 -211.341716)
		(end 298.808902 -211.341716)
		(width 0.18288)
		(layer "In4.Cu")
		(net "M_C_CPU0_SB_DQS_DN<2>")
	)
	(segment
		(start 338.875624 -230.265478)
		(end 338.622132 -230.41102)
		(width 0.088646)
		(layer "In4.Cu")
		(net "M_C_CPU0_SB_DQS_DN<2>")
	)
	(segment
		(start 317.533782 -219.077032)
		(end 317.323724 -218.569794)
		(width 0.18288)
		(layer "In4.Cu")
		(net "M_C_CPU0_SB_DQS_DN<2>")
	)
	(segment
		(start 339.132672 -230.265478)
		(end 338.875624 -230.265478)
		(width 0.088646)
		(layer "In4.Cu")
		(net "M_C_CPU0_SB_DQS_DN<2>")
	)
	(segment
		(start 295.365932 -212.46465)
		(end 295.093136 -212.191854)
		(width 0.18288)
		(layer "In4.Cu")
		(net "M_C_CPU0_SB_DQS_DN<2>")
	)
	(segment
		(start 314.808362 -212.825584)
		(end 314.452508 -212.46973)
		(width 0.18288)
		(layer "In4.Cu")
		(net "M_C_CPU0_SB_DQS_DN<2>")
	)
	(segment
		(start 288.545524 -210.77555)
		(end 287.68802 -209.918046)
		(width 0.18288)
		(layer "In4.Cu")
		(net "M_C_CPU0_SB_DQS_DN<2>")
	)
	(segment
		(start 292.503352 -211.685632)
		(end 291.59327 -210.77555)
		(width 0.18288)
		(layer "In4.Cu")
		(net "M_C_CPU0_SB_DQS_DN<2>")
	)
	(segment
		(start 298.54398 -211.606638)
		(end 298.11599 -211.606638)
		(width 0.18288)
		(layer "In4.Cu")
		(net "M_C_CPU0_SB_DQS_DN<2>")
	)
	(segment
		(start 331.92974 -230.169974)
		(end 331.524356 -229.76459)
		(width 0.088646)
		(layer "In4.Cu")
		(net "M_C_CPU0_SB_DQS_DN<2>")
	)
	(segment
		(start 336.367882 -230.41102)
		(end 336.35315 -230.402384)
		(width 0.088646)
		(layer "In4.Cu")
		(net "M_C_CPU0_SB_DQS_DN<2>")
	)
	(segment
		(start 316.43574 -216.751916)
		(end 316.50305 -216.589356)
		(width 0.18288)
		(layer "In4.Cu")
		(net "M_C_CPU0_SB_DQS_DN<2>")
	)
	(segment
		(start 280.692098 -209.475324)
		(end 280.075386 -209.475324)
		(width 0.18288)
		(layer "In4.Cu")
		(net "M_C_CPU0_SB_DQS_DN<2>")
	)
	(segment
		(start 315.92012 -215.508078)
		(end 315.98743 -215.345518)
		(width 0.18288)
		(layer "In4.Cu")
		(net "M_C_CPU0_SB_DQS_DN<2>")
	)
	(segment
		(start 335.428082 -230.41102)
		(end 335.41335 -230.402384)
		(width 0.088646)
		(layer "In4.Cu")
		(net "M_C_CPU0_SB_DQS_DN<2>")
	)
	(segment
		(start 318.35471 -221.05747)
		(end 318.191896 -220.99016)
		(width 0.18288)
		(layer "In4.Cu")
		(net "M_C_CPU0_SB_DQS_DN<2>")
	)
	(segment
		(start 330.671932 -229.173786)
		(end 330.648564 -229.173786)
		(width 0.088646)
		(layer "In4.Cu")
		(net "M_C_CPU0_SB_DQS_DN<2>")
	)
	(segment
		(start 331.08392 -229.233476)
		(end 330.731622 -229.233476)
		(width 0.088646)
		(layer "In4.Cu")
		(net "M_C_CPU0_SB_DQS_DN<2>")
	)
	(segment
		(start 317.466472 -219.239592)
		(end 317.533782 -219.077032)
		(width 0.18288)
		(layer "In4.Cu")
		(net "M_C_CPU0_SB_DQS_DN<2>")
	)
	(segment
		(start 280.075386 -209.475324)
		(end 279.816814 -209.216752)
		(width 0.18288)
		(layer "In4.Cu")
		(net "M_C_CPU0_SB_DQS_DN<2>")
	)
	(segment
		(start 325.646796 -229.173786)
		(end 318.707262 -222.233998)
		(width 0.18288)
		(layer "In4.Cu")
		(net "M_C_CPU0_SB_DQS_DN<2>")
	)
	(segment
		(start 280.896314 -209.271108)
		(end 280.692098 -209.475324)
		(width 0.18288)
		(layer "In4.Cu")
		(net "M_C_CPU0_SB_DQS_DN<2>")
	)
	(segment
		(start 315.404754 -214.26424)
		(end 315.472064 -214.10168)
		(width 0.18288)
		(layer "In4.Cu")
		(net "M_C_CPU0_SB_DQS_DN<2>")
	)
	(segment
		(start 331.524356 -229.76459)
		(end 331.524356 -229.673912)
		(width 0.088646)
		(layer "In4.Cu")
		(net "M_C_CPU0_SB_DQS_DN<2>")
	)
	(segment
		(start 332.601316 -230.406702)
		(end 332.601316 -230.40721)
		(width 0.088646)
		(layer "In4.Cu")
		(net "M_C_CPU0_SB_DQS_DN<2>")
	)
	(segment
		(start 318.049402 -220.32087)
		(end 317.839344 -219.813632)
		(width 0.18288)
		(layer "In4.Cu")
		(net "M_C_CPU0_SB_DQS_DN<2>")
	)
	(segment
		(start 298.11599 -211.606638)
		(end 297.257978 -212.46465)
		(width 0.18288)
		(layer "In4.Cu")
		(net "M_C_CPU0_SB_DQS_DN<2>")
	)
	(segment
		(start 316.292992 -216.082118)
		(end 316.129924 -216.014808)
		(width 0.18288)
		(layer "In4.Cu")
		(net "M_C_CPU0_SB_DQS_DN<2>")
	)
	(segment
		(start 316.50305 -216.589356)
		(end 316.292992 -216.082118)
		(width 0.18288)
		(layer "In4.Cu")
		(net "M_C_CPU0_SB_DQS_DN<2>")
	)
	(segment
		(start 334.488282 -230.41102)
		(end 334.47355 -230.402384)
		(width 0.088646)
		(layer "In4.Cu")
		(net "M_C_CPU0_SB_DQS_DN<2>")
	)
	(segment
		(start 283.454856 -209.906616)
		(end 282.981654 -209.906616)
		(width 0.18288)
		(layer "In4.Cu")
		(net "M_C_CPU0_SB_DQS_DN<2>")
	)
	(segment
		(start 316.808358 -217.325956)
		(end 316.645544 -217.258646)
		(width 0.18288)
		(layer "In4.Cu")
		(net "M_C_CPU0_SB_DQS_DN<2>")
	)
	(segment
		(start 282.346146 -209.271108)
		(end 280.896314 -209.271108)
		(width 0.18288)
		(layer "In4.Cu")
		(net "M_C_CPU0_SB_DQS_DN<2>")
	)
	(segment
		(start 315.262006 -213.594442)
		(end 315.098938 -213.527132)
		(width 0.18288)
		(layer "In4.Cu")
		(net "M_C_CPU0_SB_DQS_DN<2>")
	)
	(segment
		(start 282.981654 -209.906616)
		(end 282.346146 -209.271108)
		(width 0.18288)
		(layer "In4.Cu")
		(net "M_C_CPU0_SB_DQS_DN<2>")
	)
	(segment
		(start 317.839344 -219.813632)
		(end 317.676276 -219.746322)
		(width 0.18288)
		(layer "In4.Cu")
		(net "M_C_CPU0_SB_DQS_DN<2>")
	)
	(segment
		(start 316.951106 -217.995754)
		(end 317.018416 -217.833194)
		(width 0.18288)
		(layer "In4.Cu")
		(net "M_C_CPU0_SB_DQS_DN<2>")
	)
	(segment
		(start 317.16091 -218.502484)
		(end 316.951106 -217.995754)
		(width 0.18288)
		(layer "In4.Cu")
		(net "M_C_CPU0_SB_DQS_DN<2>")
	)
	(segment
		(start 299.460412 -211.624164)
		(end 299.177964 -211.341716)
		(width 0.18288)
		(layer "In4.Cu")
		(net "M_C_CPU0_SB_DQS_DN<2>")
	)
	(segment
		(start 318.707262 -222.233998)
		(end 318.497458 -221.727268)
		(width 0.18288)
		(layer "In4.Cu")
		(net "M_C_CPU0_SB_DQS_DN<2>")
	)
	(segment
		(start 298.808902 -211.341716)
		(end 298.54398 -211.606638)
		(width 0.18288)
		(layer "In4.Cu")
		(net "M_C_CPU0_SB_DQS_DN<2>")
	)
	(segment
		(start 317.676276 -219.746322)
		(end 317.466472 -219.239592)
		(width 0.18288)
		(layer "In4.Cu")
		(net "M_C_CPU0_SB_DQS_DN<2>")
	)
	(segment
		(start 315.98743 -215.345518)
		(end 315.777372 -214.83828)
		(width 0.18288)
		(layer "In4.Cu")
		(net "M_C_CPU0_SB_DQS_DN<2>")
	)
	(segment
		(start 315.777372 -214.83828)
		(end 315.614558 -214.77097)
		(width 0.18288)
		(layer "In4.Cu")
		(net "M_C_CPU0_SB_DQS_DN<2>")
	)
	(segment
		(start 313.525408 -212.34527)
		(end 312.976768 -212.34527)
		(width 0.18288)
		(layer "In4.Cu")
		(net "M_C_CPU0_SB_DQS_DN<2>")
	)
	(segment
		(start 307.67782 -211.584032)
		(end 306.944776 -210.850988)
		(width 0.18288)
		(layer "In4.Cu")
		(net "M_C_CPU0_SB_DQS_DN<2>")
	)
	(segment
		(start 317.018416 -217.833194)
		(end 316.808358 -217.325956)
		(width 0.18288)
		(layer "In4.Cu")
		(net "M_C_CPU0_SB_DQS_DN<2>")
	)
	(segment
		(start 287.68802 -209.918046)
		(end 284.450536 -209.918046)
		(width 0.18288)
		(layer "In4.Cu")
		(net "M_C_CPU0_SB_DQS_DN<2>")
	)
	(segment
		(start 316.129924 -216.014808)
		(end 315.92012 -215.508078)
		(width 0.18288)
		(layer "In4.Cu")
		(net "M_C_CPU0_SB_DQS_DN<2>")
	)
	(arc
		(start 335.802478 -230.41102)
		(mid 335.61528 -230.461163)
		(end 335.428082 -230.41102)
		(width 0.088646)
		(layer "In4.Cu")
		(net "M_C_CPU0_SB_DQS_DN<2>")
	)
	(arc
		(start 332.327504 -230.335328)
		(mid 332.11223 -230.292072)
		(end 331.92974 -230.169974)
		(width 0.088646)
		(layer "In4.Cu")
		(net "M_C_CPU0_SB_DQS_DN<2>")
	)
	(arc
		(start 337.682078 -230.41102)
		(mid 337.49488 -230.461163)
		(end 337.307682 -230.41102)
		(width 0.088646)
		(layer "In4.Cu")
		(net "M_C_CPU0_SB_DQS_DN<2>")
	)
	(arc
		(start 335.41335 -230.402384)
		(mid 335.136875 -230.335064)
		(end 334.862678 -230.41102)
		(width 0.088646)
		(layer "In4.Cu")
		(net "M_C_CPU0_SB_DQS_DN<2>")
	)
	(arc
		(start 338.622132 -230.41102)
		(mid 338.434934 -230.461163)
		(end 338.247736 -230.41102)
		(width 0.088646)
		(layer "In4.Cu")
		(net "M_C_CPU0_SB_DQS_DN<2>")
	)
	(arc
		(start 332.983078 -230.41102)
		(mid 332.79588 -230.461163)
		(end 332.608682 -230.41102)
		(width 0.088646)
		(layer "In4.Cu")
		(net "M_C_CPU0_SB_DQS_DN<2>")
	)
	(arc
		(start 338.237322 -230.404924)
		(mid 337.95889 -230.335078)
		(end 337.682078 -230.41102)
		(width 0.088646)
		(layer "In4.Cu")
		(net "M_C_CPU0_SB_DQS_DN<2>")
	)
	(arc
		(start 334.862678 -230.41102)
		(mid 334.67548 -230.461163)
		(end 334.488282 -230.41102)
		(width 0.088646)
		(layer "In4.Cu")
		(net "M_C_CPU0_SB_DQS_DN<2>")
	)
	(arc
		(start 336.35315 -230.402384)
		(mid 336.076675 -230.335064)
		(end 335.802478 -230.41102)
		(width 0.088646)
		(layer "In4.Cu")
		(net "M_C_CPU0_SB_DQS_DN<2>")
	)
	(arc
		(start 332.601316 -230.40721)
		(mid 332.468988 -230.353821)
		(end 332.327504 -230.335328)
		(width 0.088646)
		(layer "In4.Cu")
		(net "M_C_CPU0_SB_DQS_DN<2>")
	)
	(arc
		(start 339.358478 -230.144574)
		(mid 339.327433 -230.197835)
		(end 339.273896 -230.228394)
		(width 0.088646)
		(layer "In4.Cu")
		(net "M_C_CPU0_SB_DQS_DN<2>")
	)
	(arc
		(start 333.922878 -230.41102)
		(mid 333.73568 -230.461163)
		(end 333.548482 -230.41102)
		(width 0.088646)
		(layer "In4.Cu")
		(net "M_C_CPU0_SB_DQS_DN<2>")
	)
	(arc
		(start 334.47355 -230.402384)
		(mid 334.197075 -230.335064)
		(end 333.922878 -230.41102)
		(width 0.088646)
		(layer "In4.Cu")
		(net "M_C_CPU0_SB_DQS_DN<2>")
	)
	(arc
		(start 333.53375 -230.402384)
		(mid 333.257275 -230.335064)
		(end 332.983078 -230.41102)
		(width 0.088646)
		(layer "In4.Cu")
		(net "M_C_CPU0_SB_DQS_DN<2>")
	)
	(arc
		(start 337.307682 -230.41102)
		(mid 337.028479 -230.33538)
		(end 336.748374 -230.407718)
		(width 0.088646)
		(layer "In4.Cu")
		(net "M_C_CPU0_SB_DQS_DN<2>")
	)
	(arc
		(start 336.738722 -230.413306)
		(mid 336.553003 -230.461258)
		(end 336.367882 -230.41102)
		(width 0.088646)
		(layer "In4.Cu")
		(net "M_C_CPU0_SB_DQS_DN<2>")
	)
	(segment
		(start 273.127724 -219.253054)
		(end 272.491708 -218.827858)
		(width 0.20066)
		(layer "F.Cu")
		(net "M_C_CPU0_SB_DQS_DN<1>")
	)
	(segment
		(start 342.66378 -237.947454)
		(end 342.664034 -237.9472)
		(width 0.20066)
		(layer "F.Cu")
		(net "M_C_CPU0_SB_DQS_DN<1>")
	)
	(segment
		(start 274.155408 -218.991688)
		(end 274.14474 -218.98102)
		(width 0.101854)
		(layer "F.Cu")
		(net "M_C_CPU0_SB_DQS_DN<1>")
	)
	(segment
		(start 274.14474 -218.98102)
		(end 274.143978 -218.98102)
		(width 0.101854)
		(layer "F.Cu")
		(net "M_C_CPU0_SB_DQS_DN<1>")
	)
	(segment
		(start 277.072344 -219.253054)
		(end 276.885654 -219.253054)
		(width 0.20066)
		(layer "F.Cu")
		(net "M_C_CPU0_SB_DQS_DN<1>")
	)
	(segment
		(start 271.716754 -218.566746)
		(end 271.168114 -218.566746)
		(width 0.20066)
		(layer "F.Cu")
		(net "M_C_CPU0_SB_DQS_DN<1>")
	)
	(segment
		(start 276.624288 -218.991688)
		(end 276.469094 -218.991688)
		(width 0.20066)
		(layer "F.Cu")
		(net "M_C_CPU0_SB_DQS_DN<1>")
	)
	(segment
		(start 273.939762 -218.98102)
		(end 273.667728 -219.253054)
		(width 0.20066)
		(layer "F.Cu")
		(net "M_C_CPU0_SB_DQS_DN<1>")
	)
	(segment
		(start 274.143978 -218.98102)
		(end 273.939762 -218.98102)
		(width 0.20066)
		(layer "F.Cu")
		(net "M_C_CPU0_SB_DQS_DN<1>")
	)
	(segment
		(start 342.664034 -237.9472)
		(end 342.664034 -237.411514)
		(width 0.20066)
		(layer "F.Cu")
		(net "M_C_CPU0_SB_DQS_DN<1>")
	)
	(segment
		(start 277.49754 -218.827858)
		(end 277.072344 -219.253054)
		(width 0.20066)
		(layer "F.Cu")
		(net "M_C_CPU0_SB_DQS_DN<1>")
	)
	(segment
		(start 279.816814 -218.566746)
		(end 278.711914 -218.566746)
		(width 0.20066)
		(layer "F.Cu")
		(net "M_C_CPU0_SB_DQS_DN<1>")
	)
	(segment
		(start 276.885654 -219.253054)
		(end 276.624288 -218.991688)
		(width 0.20066)
		(layer "F.Cu")
		(net "M_C_CPU0_SB_DQS_DN<1>")
	)
	(segment
		(start 272.491708 -218.827858)
		(end 271.977866 -218.827858)
		(width 0.20066)
		(layer "F.Cu")
		(net "M_C_CPU0_SB_DQS_DN<1>")
	)
	(segment
		(start 273.667728 -219.253054)
		(end 273.127724 -219.253054)
		(width 0.20066)
		(layer "F.Cu")
		(net "M_C_CPU0_SB_DQS_DN<1>")
	)
	(segment
		(start 278.711914 -218.566746)
		(end 278.165306 -218.566746)
		(width 0.20066)
		(layer "F.Cu")
		(net "M_C_CPU0_SB_DQS_DN<1>")
	)
	(segment
		(start 271.977866 -218.827858)
		(end 271.716754 -218.566746)
		(width 0.20066)
		(layer "F.Cu")
		(net "M_C_CPU0_SB_DQS_DN<1>")
	)
	(segment
		(start 278.165306 -218.566746)
		(end 277.904194 -218.827858)
		(width 0.20066)
		(layer "F.Cu")
		(net "M_C_CPU0_SB_DQS_DN<1>")
	)
	(segment
		(start 276.469094 -218.991688)
		(end 274.155408 -218.991688)
		(width 0.1016)
		(layer "F.Cu")
		(net "M_C_CPU0_SB_DQS_DN<1>")
	)
	(segment
		(start 277.904194 -218.827858)
		(end 277.49754 -218.827858)
		(width 0.20066)
		(layer "F.Cu")
		(net "M_C_CPU0_SB_DQS_DN<1>")
	)
	(segment
		(start 314.533788 -226.046538)
		(end 314.280804 -225.793554)
		(width 0.18288)
		(layer "In6.Cu")
		(net "M_C_CPU0_SB_DQS_DN<1>")
	)
	(segment
		(start 308.142894 -222.66529)
		(end 306.69103 -222.063818)
		(width 0.18288)
		(layer "In6.Cu")
		(net "M_C_CPU0_SB_DQS_DN<1>")
	)
	(segment
		(start 311.32145 -224.23628)
		(end 311.062624 -223.752156)
		(width 0.18288)
		(layer "In6.Cu")
		(net "M_C_CPU0_SB_DQS_DN<1>")
	)
	(segment
		(start 339.657182 -237.736126)
		(end 339.646768 -237.73003)
		(width 0.088646)
		(layer "In6.Cu")
		(net "M_C_CPU0_SB_DQS_DN<1>")
	)
	(segment
		(start 299.512736 -222.639382)
		(end 299.262292 -222.388938)
		(width 0.18288)
		(layer "In6.Cu")
		(net "M_C_CPU0_SB_DQS_DN<1>")
	)
	(segment
		(start 286.15132 -219.273882)
		(end 284.428946 -219.273882)
		(width 0.18288)
		(layer "In6.Cu")
		(net "M_C_CPU0_SB_DQS_DN<1>")
	)
	(segment
		(start 313.103768 -226.056952)
		(end 312.459624 -225.412554)
		(width 0.18288)
		(layer "In6.Cu")
		(net "M_C_CPU0_SB_DQS_DN<1>")
	)
	(segment
		(start 288.679636 -219.628974)
		(end 288.172652 -219.418916)
		(width 0.18288)
		(layer "In6.Cu")
		(net "M_C_CPU0_SB_DQS_DN<1>")
	)
	(segment
		(start 290.326826 -220.961966)
		(end 290.32708 -220.785944)
		(width 0.18288)
		(layer "In6.Cu")
		(net "M_C_CPU0_SB_DQS_DN<1>")
	)
	(segment
		(start 283.664406 -218.993212)
		(end 283.401262 -219.256356)
		(width 0.18288)
		(layer "In6.Cu")
		(net "M_C_CPU0_SB_DQS_DN<1>")
	)
	(segment
		(start 301.01413 -222.639382)
		(end 299.512736 -222.639382)
		(width 0.18288)
		(layer "In6.Cu")
		(net "M_C_CPU0_SB_DQS_DN<1>")
	)
	(segment
		(start 280.84907 -218.628976)
		(end 280.360628 -218.83116)
		(width 0.18288)
		(layer "In6.Cu")
		(net "M_C_CPU0_SB_DQS_DN<1>")
	)
	(segment
		(start 283.401262 -219.256356)
		(end 283.081476 -219.256356)
		(width 0.18288)
		(layer "In6.Cu")
		(net "M_C_CPU0_SB_DQS_DN<1>")
	)
	(segment
		(start 298.196508 -222.635826)
		(end 297.383962 -221.822772)
		(width 0.18288)
		(layer "In6.Cu")
		(net "M_C_CPU0_SB_DQS_DN<1>")
	)
	(segment
		(start 331.631544 -236.587538)
		(end 331.631544 -236.239558)
		(width 0.088646)
		(layer "In6.Cu")
		(net "M_C_CPU0_SB_DQS_DN<1>")
	)
	(segment
		(start 332.0542 -236.916214)
		(end 332.054454 -236.916468)
		(width 0.088646)
		(layer "In6.Cu")
		(net "M_C_CPU0_SB_DQS_DN<1>")
	)
	(segment
		(start 288.746946 -219.791788)
		(end 288.679636 -219.628974)
		(width 0.18288)
		(layer "In6.Cu")
		(net "M_C_CPU0_SB_DQS_DN<1>")
	)
	(segment
		(start 288.172652 -219.418916)
		(end 288.010092 -219.486226)
		(width 0.18288)
		(layer "In6.Cu")
		(net "M_C_CPU0_SB_DQS_DN<1>")
	)
	(segment
		(start 332.998064 -236.913674)
		(end 332.983332 -236.92231)
		(width 0.088646)
		(layer "In6.Cu")
		(net "M_C_CPU0_SB_DQS_DN<1>")
	)
	(segment
		(start 295.143174 -221.540324)
		(end 294.664892 -221.540324)
		(width 0.18288)
		(layer "In6.Cu")
		(net "M_C_CPU0_SB_DQS_DN<1>")
	)
	(segment
		(start 294.053768 -221.806262)
		(end 293.74973 -221.50197)
		(width 0.18288)
		(layer "In6.Cu")
		(net "M_C_CPU0_SB_DQS_DN<1>")
	)
	(segment
		(start 311.528714 -224.888552)
		(end 311.270142 -224.404682)
		(width 0.18288)
		(layer "In6.Cu")
		(net "M_C_CPU0_SB_DQS_DN<1>")
	)
	(segment
		(start 301.81169 -222.639382)
		(end 301.68723 -222.514922)
		(width 0.18288)
		(layer "In6.Cu")
		(net "M_C_CPU0_SB_DQS_DN<1>")
	)
	(segment
		(start 309.799482 -222.66529)
		(end 308.142894 -222.66529)
		(width 0.18288)
		(layer "In6.Cu")
		(net "M_C_CPU0_SB_DQS_DN<1>")
	)
	(segment
		(start 335.341468 -237.730792)
		(end 335.332578 -237.736126)
		(width 0.088646)
		(layer "In6.Cu")
		(net "M_C_CPU0_SB_DQS_DN<1>")
	)
	(segment
		(start 304.376582 -221.939358)
		(end 303.827942 -221.939358)
		(width 0.18288)
		(layer "In6.Cu")
		(net "M_C_CPU0_SB_DQS_DN<1>")
	)
	(segment
		(start 290.714684 -221.349824)
		(end 290.326826 -220.961966)
		(width 0.18288)
		(layer "In6.Cu")
		(net "M_C_CPU0_SB_DQS_DN<1>")
	)
	(segment
		(start 338.166964 -237.72749)
		(end 338.152232 -237.736126)
		(width 0.088646)
		(layer "In6.Cu")
		(net "M_C_CPU0_SB_DQS_DN<1>")
	)
	(segment
		(start 284.428946 -219.273882)
		(end 284.148276 -218.993212)
		(width 0.18288)
		(layer "In6.Cu")
		(net "M_C_CPU0_SB_DQS_DN<1>")
	)
	(segment
		(start 287.49752 -219.273882)
		(end 286.94888 -219.273882)
		(width 0.18288)
		(layer "In6.Cu")
		(net "M_C_CPU0_SB_DQS_DN<1>")
	)
	(segment
		(start 340.041992 -237.729776)
		(end 340.031578 -237.735872)
		(width 0.088646)
		(layer "In6.Cu")
		(net "M_C_CPU0_SB_DQS_DN<1>")
	)
	(segment
		(start 331.55255 -236.160564)
		(end 331.55255 -235.703618)
		(width 0.088646)
		(layer "In6.Cu")
		(net "M_C_CPU0_SB_DQS_DN<1>")
	)
	(segment
		(start 280.360628 -218.83116)
		(end 280.081228 -218.83116)
		(width 0.18288)
		(layer "In6.Cu")
		(net "M_C_CPU0_SB_DQS_DN<1>")
	)
	(segment
		(start 313.88177 -225.793554)
		(end 313.618372 -226.056952)
		(width 0.18288)
		(layer "In6.Cu")
		(net "M_C_CPU0_SB_DQS_DN<1>")
	)
	(segment
		(start 296.125138 -221.822772)
		(end 295.425622 -221.822772)
		(width 0.18288)
		(layer "In6.Cu")
		(net "M_C_CPU0_SB_DQS_DN<1>")
	)
	(segment
		(start 295.425622 -221.822772)
		(end 295.143174 -221.540324)
		(width 0.18288)
		(layer "In6.Cu")
		(net "M_C_CPU0_SB_DQS_DN<1>")
	)
	(segment
		(start 331.631544 -236.239558)
		(end 331.55255 -236.160564)
		(width 0.088646)
		(layer "In6.Cu")
		(net "M_C_CPU0_SB_DQS_DN<1>")
	)
	(segment
		(start 280.081228 -218.83116)
		(end 279.816814 -218.566746)
		(width 0.18288)
		(layer "In6.Cu")
		(net "M_C_CPU0_SB_DQS_DN<1>")
	)
	(segment
		(start 306.69103 -222.063818)
		(end 305.847242 -222.063818)
		(width 0.18288)
		(layer "In6.Cu")
		(net "M_C_CPU0_SB_DQS_DN<1>")
	)
	(segment
		(start 293.067994 -221.219776)
		(end 292.4937 -221.219776)
		(width 0.18288)
		(layer "In6.Cu")
		(net "M_C_CPU0_SB_DQS_DN<1>")
	)
	(segment
		(start 303.827942 -221.939358)
		(end 303.703482 -222.063818)
		(width 0.18288)
		(layer "In6.Cu")
		(net "M_C_CPU0_SB_DQS_DN<1>")
	)
	(segment
		(start 283.081476 -219.256356)
		(end 282.454096 -218.628976)
		(width 0.18288)
		(layer "In6.Cu")
		(net "M_C_CPU0_SB_DQS_DN<1>")
	)
	(segment
		(start 286.27578 -219.149422)
		(end 286.15132 -219.273882)
		(width 0.18288)
		(layer "In6.Cu")
		(net "M_C_CPU0_SB_DQS_DN<1>")
	)
	(segment
		(start 331.978762 -236.934756)
		(end 331.631544 -236.587538)
		(width 0.088646)
		(layer "In6.Cu")
		(net "M_C_CPU0_SB_DQS_DN<1>")
	)
	(segment
		(start 289.447478 -220.08211)
		(end 288.746946 -219.791788)
		(width 0.18288)
		(layer "In6.Cu")
		(net "M_C_CPU0_SB_DQS_DN<1>")
	)
	(segment
		(start 289.762692 -220.397578)
		(end 289.447478 -220.08211)
		(width 0.18288)
		(layer "In6.Cu")
		(net "M_C_CPU0_SB_DQS_DN<1>")
	)
	(segment
		(start 303.154842 -222.063818)
		(end 302.579278 -222.639382)
		(width 0.18288)
		(layer "In6.Cu")
		(net "M_C_CPU0_SB_DQS_DN<1>")
	)
	(segment
		(start 340.031578 -237.735872)
		(end 340.031578 -237.736126)
		(width 0.088646)
		(layer "In6.Cu")
		(net "M_C_CPU0_SB_DQS_DN<1>")
	)
	(segment
		(start 330.775564 -235.206032)
		(end 322.502022 -235.206032)
		(width 0.18288)
		(layer "In6.Cu")
		(net "M_C_CPU0_SB_DQS_DN<1>")
	)
	(segment
		(start 304.501042 -222.063818)
		(end 304.376582 -221.939358)
		(width 0.18288)
		(layer "In6.Cu")
		(net "M_C_CPU0_SB_DQS_DN<1>")
	)
	(segment
		(start 330.858622 -235.265722)
		(end 330.798932 -235.206032)
		(width 0.088646)
		(layer "In6.Cu")
		(net "M_C_CPU0_SB_DQS_DN<1>")
	)
	(segment
		(start 298.499022 -222.635826)
		(end 298.196508 -222.635826)
		(width 0.18288)
		(layer "In6.Cu")
		(net "M_C_CPU0_SB_DQS_DN<1>")
	)
	(segment
		(start 289.938714 -220.397578)
		(end 289.762692 -220.397578)
		(width 0.18288)
		(layer "In6.Cu")
		(net "M_C_CPU0_SB_DQS_DN<1>")
	)
	(segment
		(start 311.062624 -223.752156)
		(end 310.894222 -223.701102)
		(width 0.18288)
		(layer "In6.Cu")
		(net "M_C_CPU0_SB_DQS_DN<1>")
	)
	(segment
		(start 281.889708 -218.504516)
		(end 281.341068 -218.504516)
		(width 0.18288)
		(layer "In6.Cu")
		(net "M_C_CPU0_SB_DQS_DN<1>")
	)
	(segment
		(start 291.681662 -221.556072)
		(end 291.211762 -221.556072)
		(width 0.18288)
		(layer "In6.Cu")
		(net "M_C_CPU0_SB_DQS_DN<1>")
	)
	(segment
		(start 305.174142 -221.939358)
		(end 305.049682 -222.063818)
		(width 0.18288)
		(layer "In6.Cu")
		(net "M_C_CPU0_SB_DQS_DN<1>")
	)
	(segment
		(start 322.502022 -235.206032)
		(end 315.416184 -228.120194)
		(width 0.18288)
		(layer "In6.Cu")
		(net "M_C_CPU0_SB_DQS_DN<1>")
	)
	(segment
		(start 311.764934 -225.124772)
		(end 311.528714 -224.888552)
		(width 0.18288)
		(layer "In6.Cu")
		(net "M_C_CPU0_SB_DQS_DN<1>")
	)
	(segment
		(start 288.010092 -219.486226)
		(end 287.49752 -219.273882)
		(width 0.18288)
		(layer "In6.Cu")
		(net "M_C_CPU0_SB_DQS_DN<1>")
	)
	(segment
		(start 342.165178 -237.59033)
		(end 341.91194 -237.736126)
		(width 0.088646)
		(layer "In6.Cu")
		(net "M_C_CPU0_SB_DQS_DN<1>")
	)
	(segment
		(start 305.049682 -222.063818)
		(end 304.501042 -222.063818)
		(width 0.18288)
		(layer "In6.Cu")
		(net "M_C_CPU0_SB_DQS_DN<1>")
	)
	(segment
		(start 313.618372 -226.056952)
		(end 313.103768 -226.056952)
		(width 0.18288)
		(layer "In6.Cu")
		(net "M_C_CPU0_SB_DQS_DN<1>")
	)
	(segment
		(start 310.894222 -223.701102)
		(end 310.494172 -222.952564)
		(width 0.18288)
		(layer "In6.Cu")
		(net "M_C_CPU0_SB_DQS_DN<1>")
	)
	(segment
		(start 296.249598 -221.698312)
		(end 296.125138 -221.822772)
		(width 0.18288)
		(layer "In6.Cu")
		(net "M_C_CPU0_SB_DQS_DN<1>")
	)
	(segment
		(start 281.341068 -218.504516)
		(end 281.216608 -218.628976)
		(width 0.18288)
		(layer "In6.Cu")
		(net "M_C_CPU0_SB_DQS_DN<1>")
	)
	(segment
		(start 315.416184 -228.120194)
		(end 315.416184 -226.499928)
		(width 0.18288)
		(layer "In6.Cu")
		(net "M_C_CPU0_SB_DQS_DN<1>")
	)
	(segment
		(start 286.94888 -219.273882)
		(end 286.82442 -219.149422)
		(width 0.18288)
		(layer "In6.Cu")
		(net "M_C_CPU0_SB_DQS_DN<1>")
	)
	(segment
		(start 303.703482 -222.063818)
		(end 303.154842 -222.063818)
		(width 0.18288)
		(layer "In6.Cu")
		(net "M_C_CPU0_SB_DQS_DN<1>")
	)
	(segment
		(start 305.847242 -222.063818)
		(end 305.722782 -221.939358)
		(width 0.18288)
		(layer "In6.Cu")
		(net "M_C_CPU0_SB_DQS_DN<1>")
	)
	(segment
		(start 302.579278 -222.639382)
		(end 301.81169 -222.639382)
		(width 0.18288)
		(layer "In6.Cu")
		(net "M_C_CPU0_SB_DQS_DN<1>")
	)
	(segment
		(start 337.777836 -237.736126)
		(end 337.777836 -237.735872)
		(width 0.088646)
		(layer "In6.Cu")
		(net "M_C_CPU0_SB_DQS_DN<1>")
	)
	(segment
		(start 305.722782 -221.939358)
		(end 305.174142 -221.939358)
		(width 0.18288)
		(layer "In6.Cu")
		(net "M_C_CPU0_SB_DQS_DN<1>")
	)
	(segment
		(start 331.55255 -235.703618)
		(end 331.114654 -235.265722)
		(width 0.088646)
		(layer "In6.Cu")
		(net "M_C_CPU0_SB_DQS_DN<1>")
	)
	(segment
		(start 333.56423 -236.931708)
		(end 333.548736 -236.92231)
		(width 0.088646)
		(layer "In6.Cu")
		(net "M_C_CPU0_SB_DQS_DN<1>")
	)
	(segment
		(start 296.798238 -221.698312)
		(end 296.249598 -221.698312)
		(width 0.18288)
		(layer "In6.Cu")
		(net "M_C_CPU0_SB_DQS_DN<1>")
	)
	(segment
		(start 341.53729 -237.735872)
		(end 341.537036 -237.735872)
		(width 0.088646)
		(layer "In6.Cu")
		(net "M_C_CPU0_SB_DQS_DN<1>")
	)
	(segment
		(start 301.68723 -222.514922)
		(end 301.13859 -222.514922)
		(width 0.18288)
		(layer "In6.Cu")
		(net "M_C_CPU0_SB_DQS_DN<1>")
	)
	(segment
		(start 286.82442 -219.149422)
		(end 286.27578 -219.149422)
		(width 0.18288)
		(layer "In6.Cu")
		(net "M_C_CPU0_SB_DQS_DN<1>")
	)
	(segment
		(start 298.74591 -222.388938)
		(end 298.499022 -222.635826)
		(width 0.18288)
		(layer "In6.Cu")
		(net "M_C_CPU0_SB_DQS_DN<1>")
	)
	(segment
		(start 314.280804 -225.793554)
		(end 313.88177 -225.793554)
		(width 0.18288)
		(layer "In6.Cu")
		(net "M_C_CPU0_SB_DQS_DN<1>")
	)
	(segment
		(start 342.664034 -237.411514)
		(end 342.632284 -237.527338)
		(width 0.088646)
		(layer "In6.Cu")
		(net "M_C_CPU0_SB_DQS_DN<1>")
	)
	(segment
		(start 293.74973 -221.50197)
		(end 293.067994 -221.219776)
		(width 0.18288)
		(layer "In6.Cu")
		(net "M_C_CPU0_SB_DQS_DN<1>")
	)
	(segment
		(start 282.454096 -218.628976)
		(end 282.014168 -218.628976)
		(width 0.18288)
		(layer "In6.Cu")
		(net "M_C_CPU0_SB_DQS_DN<1>")
	)
	(segment
		(start 282.014168 -218.628976)
		(end 281.889708 -218.504516)
		(width 0.18288)
		(layer "In6.Cu")
		(net "M_C_CPU0_SB_DQS_DN<1>")
	)
	(segment
		(start 314.962794 -226.046538)
		(end 314.533788 -226.046538)
		(width 0.18288)
		(layer "In6.Cu")
		(net "M_C_CPU0_SB_DQS_DN<1>")
	)
	(segment
		(start 311.270142 -224.404682)
		(end 311.32145 -224.23628)
		(width 0.18288)
		(layer "In6.Cu")
		(net "M_C_CPU0_SB_DQS_DN<1>")
	)
	(segment
		(start 342.632284 -237.527338)
		(end 342.593422 -237.549436)
		(width 0.088646)
		(layer "In6.Cu")
		(net "M_C_CPU0_SB_DQS_DN<1>")
	)
	(segment
		(start 337.227164 -237.727236)
		(end 337.212432 -237.735872)
		(width 0.088646)
		(layer "In6.Cu")
		(net "M_C_CPU0_SB_DQS_DN<1>")
	)
	(segment
		(start 292.4937 -221.219776)
		(end 291.681662 -221.556072)
		(width 0.18288)
		(layer "In6.Cu")
		(net "M_C_CPU0_SB_DQS_DN<1>")
	)
	(segment
		(start 291.211762 -221.556072)
		(end 290.714684 -221.349824)
		(width 0.18288)
		(layer "In6.Cu")
		(net "M_C_CPU0_SB_DQS_DN<1>")
	)
	(segment
		(start 297.383962 -221.822772)
		(end 296.922698 -221.822772)
		(width 0.18288)
		(layer "In6.Cu")
		(net "M_C_CPU0_SB_DQS_DN<1>")
	)
	(segment
		(start 330.798932 -235.206032)
		(end 330.775564 -235.206032)
		(width 0.088646)
		(layer "In6.Cu")
		(net "M_C_CPU0_SB_DQS_DN<1>")
	)
	(segment
		(start 301.13859 -222.514922)
		(end 301.01413 -222.639382)
		(width 0.18288)
		(layer "In6.Cu")
		(net "M_C_CPU0_SB_DQS_DN<1>")
	)
	(segment
		(start 310.494172 -222.952564)
		(end 309.799482 -222.66529)
		(width 0.18288)
		(layer "In6.Cu")
		(net "M_C_CPU0_SB_DQS_DN<1>")
	)
	(segment
		(start 336.287364 -237.727236)
		(end 336.272632 -237.735872)
		(width 0.088646)
		(layer "In6.Cu")
		(net "M_C_CPU0_SB_DQS_DN<1>")
	)
	(segment
		(start 294.664892 -221.540324)
		(end 294.398954 -221.806262)
		(width 0.18288)
		(layer "In6.Cu")
		(net "M_C_CPU0_SB_DQS_DN<1>")
	)
	(segment
		(start 340.986364 -237.727236)
		(end 340.971632 -237.735872)
		(width 0.088646)
		(layer "In6.Cu")
		(net "M_C_CPU0_SB_DQS_DN<1>")
	)
	(segment
		(start 281.216608 -218.628976)
		(end 280.84907 -218.628976)
		(width 0.18288)
		(layer "In6.Cu")
		(net "M_C_CPU0_SB_DQS_DN<1>")
	)
	(segment
		(start 315.416184 -226.499928)
		(end 314.962794 -226.046538)
		(width 0.18288)
		(layer "In6.Cu")
		(net "M_C_CPU0_SB_DQS_DN<1>")
	)
	(segment
		(start 331.114654 -235.265722)
		(end 330.858622 -235.265722)
		(width 0.088646)
		(layer "In6.Cu")
		(net "M_C_CPU0_SB_DQS_DN<1>")
	)
	(segment
		(start 342.438736 -237.59033)
		(end 342.165178 -237.59033)
		(width 0.088646)
		(layer "In6.Cu")
		(net "M_C_CPU0_SB_DQS_DN<1>")
	)
	(segment
		(start 284.148276 -218.993212)
		(end 283.664406 -218.993212)
		(width 0.18288)
		(layer "In6.Cu")
		(net "M_C_CPU0_SB_DQS_DN<1>")
	)
	(segment
		(start 296.922698 -221.822772)
		(end 296.798238 -221.698312)
		(width 0.18288)
		(layer "In6.Cu")
		(net "M_C_CPU0_SB_DQS_DN<1>")
	)
	(segment
		(start 294.398954 -221.806262)
		(end 294.053768 -221.806262)
		(width 0.18288)
		(layer "In6.Cu")
		(net "M_C_CPU0_SB_DQS_DN<1>")
	)
	(segment
		(start 341.91194 -237.736126)
		(end 341.911686 -237.735872)
		(width 0.088646)
		(layer "In6.Cu")
		(net "M_C_CPU0_SB_DQS_DN<1>")
	)
	(segment
		(start 290.32708 -220.785944)
		(end 289.938714 -220.397578)
		(width 0.18288)
		(layer "In6.Cu")
		(net "M_C_CPU0_SB_DQS_DN<1>")
	)
	(segment
		(start 334.403446 -237.73003)
		(end 334.393032 -237.736126)
		(width 0.088646)
		(layer "In6.Cu")
		(net "M_C_CPU0_SB_DQS_DN<1>")
	)
	(segment
		(start 299.262292 -222.388938)
		(end 298.74591 -222.388938)
		(width 0.18288)
		(layer "In6.Cu")
		(net "M_C_CPU0_SB_DQS_DN<1>")
	)
	(segment
		(start 312.459624 -225.412554)
		(end 311.764934 -225.124772)
		(width 0.18288)
		(layer "In6.Cu")
		(net "M_C_CPU0_SB_DQS_DN<1>")
	)
	(segment
		(start 332.0161 -236.934756)
		(end 331.978762 -236.934756)
		(width 0.088646)
		(layer "In6.Cu")
		(net "M_C_CPU0_SB_DQS_DN<1>")
	)
	(arc
		(start 335.898236 -237.735872)
		(mid 335.62051 -237.660027)
		(end 335.341468 -237.730792)
		(width 0.088646)
		(layer "In6.Cu")
		(net "M_C_CPU0_SB_DQS_DN<1>")
	)
	(arc
		(start 332.983332 -236.92231)
		(mid 332.796134 -236.972453)
		(end 332.608936 -236.92231)
		(width 0.088646)
		(layer "In6.Cu")
		(net "M_C_CPU0_SB_DQS_DN<1>")
	)
	(arc
		(start 337.212432 -237.735872)
		(mid 337.025234 -237.786015)
		(end 336.838036 -237.735872)
		(width 0.088646)
		(layer "In6.Cu")
		(net "M_C_CPU0_SB_DQS_DN<1>")
	)
	(arc
		(start 338.717636 -237.736126)
		(mid 338.443437 -237.660291)
		(end 338.166964 -237.72749)
		(width 0.088646)
		(layer "In6.Cu")
		(net "M_C_CPU0_SB_DQS_DN<1>")
	)
	(arc
		(start 341.537036 -237.735872)
		(mid 341.262807 -237.659947)
		(end 340.986364 -237.727236)
		(width 0.088646)
		(layer "In6.Cu")
		(net "M_C_CPU0_SB_DQS_DN<1>")
	)
	(arc
		(start 333.831184 -237.411768)
		(mid 333.759959 -237.137118)
		(end 333.56423 -236.931708)
		(width 0.088646)
		(layer "In6.Cu")
		(net "M_C_CPU0_SB_DQS_DN<1>")
	)
	(arc
		(start 339.092032 -237.736126)
		(mid 338.904834 -237.786269)
		(end 338.717636 -237.736126)
		(width 0.088646)
		(layer "In6.Cu")
		(net "M_C_CPU0_SB_DQS_DN<1>")
	)
	(arc
		(start 332.608936 -236.92231)
		(mid 332.332377 -236.846567)
		(end 332.0542 -236.916214)
		(width 0.088646)
		(layer "In6.Cu")
		(net "M_C_CPU0_SB_DQS_DN<1>")
	)
	(arc
		(start 340.971632 -237.735872)
		(mid 340.784434 -237.786015)
		(end 340.597236 -237.735872)
		(width 0.088646)
		(layer "In6.Cu")
		(net "M_C_CPU0_SB_DQS_DN<1>")
	)
	(arc
		(start 338.152232 -237.736126)
		(mid 337.965034 -237.786269)
		(end 337.777836 -237.736126)
		(width 0.088646)
		(layer "In6.Cu")
		(net "M_C_CPU0_SB_DQS_DN<1>")
	)
	(arc
		(start 336.272632 -237.735872)
		(mid 336.085434 -237.786015)
		(end 335.898236 -237.735872)
		(width 0.088646)
		(layer "In6.Cu")
		(net "M_C_CPU0_SB_DQS_DN<1>")
	)
	(arc
		(start 334.393032 -237.736126)
		(mid 334.018557 -237.73608)
		(end 333.831184 -237.411768)
		(width 0.088646)
		(layer "In6.Cu")
		(net "M_C_CPU0_SB_DQS_DN<1>")
	)
	(arc
		(start 341.911686 -237.735872)
		(mid 341.724488 -237.786015)
		(end 341.53729 -237.735872)
		(width 0.088646)
		(layer "In6.Cu")
		(net "M_C_CPU0_SB_DQS_DN<1>")
	)
	(arc
		(start 342.593422 -237.549436)
		(mid 342.518737 -237.579941)
		(end 342.438736 -237.59033)
		(width 0.088646)
		(layer "In6.Cu")
		(net "M_C_CPU0_SB_DQS_DN<1>")
	)
	(arc
		(start 340.031578 -237.736126)
		(mid 339.84438 -237.786269)
		(end 339.657182 -237.736126)
		(width 0.088646)
		(layer "In6.Cu")
		(net "M_C_CPU0_SB_DQS_DN<1>")
	)
	(arc
		(start 335.332578 -237.736126)
		(mid 335.14538 -237.786269)
		(end 334.958182 -237.736126)
		(width 0.088646)
		(layer "In6.Cu")
		(net "M_C_CPU0_SB_DQS_DN<1>")
	)
	(arc
		(start 339.646768 -237.73003)
		(mid 339.36859 -237.660307)
		(end 339.092032 -237.736126)
		(width 0.088646)
		(layer "In6.Cu")
		(net "M_C_CPU0_SB_DQS_DN<1>")
	)
	(arc
		(start 340.597236 -237.735872)
		(mid 340.320423 -237.660036)
		(end 340.041992 -237.729776)
		(width 0.088646)
		(layer "In6.Cu")
		(net "M_C_CPU0_SB_DQS_DN<1>")
	)
	(arc
		(start 337.777836 -237.735872)
		(mid 337.503607 -237.659947)
		(end 337.227164 -237.727236)
		(width 0.088646)
		(layer "In6.Cu")
		(net "M_C_CPU0_SB_DQS_DN<1>")
	)
	(arc
		(start 333.548736 -236.92231)
		(mid 333.274537 -236.846475)
		(end 332.998064 -236.913674)
		(width 0.088646)
		(layer "In6.Cu")
		(net "M_C_CPU0_SB_DQS_DN<1>")
	)
	(arc
		(start 336.838036 -237.735872)
		(mid 336.563807 -237.659947)
		(end 336.287364 -237.727236)
		(width 0.088646)
		(layer "In6.Cu")
		(net "M_C_CPU0_SB_DQS_DN<1>")
	)
	(arc
		(start 332.054454 -236.916468)
		(mid 332.035535 -236.926154)
		(end 332.0161 -236.934756)
		(width 0.088646)
		(layer "In6.Cu")
		(net "M_C_CPU0_SB_DQS_DN<1>")
	)
	(arc
		(start 334.958182 -237.736126)
		(mid 334.681623 -237.660383)
		(end 334.403446 -237.73003)
		(width 0.088646)
		(layer "In6.Cu")
		(net "M_C_CPU0_SB_DQS_DN<1>")
	)
	(segment
		(start 277.072344 -228.603048)
		(end 276.885654 -228.603048)
		(width 0.20066)
		(layer "F.Cu")
		(net "M_C_CPU0_SB_DQS_DN<0>")
	)
	(segment
		(start 279.816814 -227.91674)
		(end 278.711914 -227.91674)
		(width 0.20066)
		(layer "F.Cu")
		(net "M_C_CPU0_SB_DQS_DN<0>")
	)
	(segment
		(start 276.624288 -228.341682)
		(end 276.469094 -228.341682)
		(width 0.20066)
		(layer "F.Cu")
		(net "M_C_CPU0_SB_DQS_DN<0>")
	)
	(segment
		(start 342.66378 -242.830858)
		(end 342.664034 -242.294918)
		(width 0.20066)
		(layer "F.Cu")
		(net "M_C_CPU0_SB_DQS_DN<0>")
	)
	(segment
		(start 278.711914 -227.91674)
		(end 278.165306 -227.91674)
		(width 0.20066)
		(layer "F.Cu")
		(net "M_C_CPU0_SB_DQS_DN<0>")
	)
	(segment
		(start 276.469094 -228.341682)
		(end 274.155408 -228.341682)
		(width 0.1016)
		(layer "F.Cu")
		(net "M_C_CPU0_SB_DQS_DN<0>")
	)
	(segment
		(start 274.14474 -228.331014)
		(end 274.143978 -228.331014)
		(width 0.101854)
		(layer "F.Cu")
		(net "M_C_CPU0_SB_DQS_DN<0>")
	)
	(segment
		(start 273.939762 -228.331014)
		(end 273.667728 -228.603048)
		(width 0.20066)
		(layer "F.Cu")
		(net "M_C_CPU0_SB_DQS_DN<0>")
	)
	(segment
		(start 277.904194 -228.177852)
		(end 277.49754 -228.177852)
		(width 0.20066)
		(layer "F.Cu")
		(net "M_C_CPU0_SB_DQS_DN<0>")
	)
	(segment
		(start 278.165306 -227.91674)
		(end 277.904194 -228.177852)
		(width 0.20066)
		(layer "F.Cu")
		(net "M_C_CPU0_SB_DQS_DN<0>")
	)
	(segment
		(start 271.716754 -227.91674)
		(end 271.168114 -227.91674)
		(width 0.20066)
		(layer "F.Cu")
		(net "M_C_CPU0_SB_DQS_DN<0>")
	)
	(segment
		(start 277.49754 -228.177852)
		(end 277.072344 -228.603048)
		(width 0.20066)
		(layer "F.Cu")
		(net "M_C_CPU0_SB_DQS_DN<0>")
	)
	(segment
		(start 272.492724 -228.177852)
		(end 271.977866 -228.177852)
		(width 0.20066)
		(layer "F.Cu")
		(net "M_C_CPU0_SB_DQS_DN<0>")
	)
	(segment
		(start 271.977866 -228.177852)
		(end 271.716754 -227.91674)
		(width 0.20066)
		(layer "F.Cu")
		(net "M_C_CPU0_SB_DQS_DN<0>")
	)
	(segment
		(start 274.143978 -228.331014)
		(end 273.939762 -228.331014)
		(width 0.20066)
		(layer "F.Cu")
		(net "M_C_CPU0_SB_DQS_DN<0>")
	)
	(segment
		(start 273.667728 -228.603048)
		(end 273.127724 -228.603048)
		(width 0.20066)
		(layer "F.Cu")
		(net "M_C_CPU0_SB_DQS_DN<0>")
	)
	(segment
		(start 274.155408 -228.341682)
		(end 274.14474 -228.331014)
		(width 0.101854)
		(layer "F.Cu")
		(net "M_C_CPU0_SB_DQS_DN<0>")
	)
	(segment
		(start 276.885654 -228.603048)
		(end 276.624288 -228.341682)
		(width 0.20066)
		(layer "F.Cu")
		(net "M_C_CPU0_SB_DQS_DN<0>")
	)
	(segment
		(start 273.127724 -228.603048)
		(end 272.492724 -228.177852)
		(width 0.20066)
		(layer "F.Cu")
		(net "M_C_CPU0_SB_DQS_DN<0>")
	)
	(segment
		(start 283.439362 -228.59619)
		(end 282.959048 -228.59619)
		(width 0.18288)
		(layer "In6.Cu")
		(net "M_C_CPU0_SB_DQS_DN<0>")
	)
	(segment
		(start 298.526962 -233.696002)
		(end 298.211748 -233.696002)
		(width 0.18288)
		(layer "In6.Cu")
		(net "M_C_CPU0_SB_DQS_DN<0>")
	)
	(segment
		(start 286.427926 -229.65918)
		(end 286.427926 -229.483158)
		(width 0.18288)
		(layer "In6.Cu")
		(net "M_C_CPU0_SB_DQS_DN<0>")
	)
	(segment
		(start 299.553122 -233.712004)
		(end 299.282866 -233.441748)
		(width 0.18288)
		(layer "In6.Cu")
		(net "M_C_CPU0_SB_DQS_DN<0>")
	)
	(segment
		(start 300.162976 -233.712004)
		(end 299.553122 -233.712004)
		(width 0.18288)
		(layer "In6.Cu")
		(net "M_C_CPU0_SB_DQS_DN<0>")
	)
	(segment
		(start 335.897982 -242.61953)
		(end 335.89849 -242.619276)
		(width 0.088646)
		(layer "In6.Cu")
		(net "M_C_CPU0_SB_DQS_DN<0>")
	)
	(segment
		(start 290.604448 -230.897938)
		(end 288.883344 -230.897938)
		(width 0.18288)
		(layer "In6.Cu")
		(net "M_C_CPU0_SB_DQS_DN<0>")
	)
	(segment
		(start 286.427926 -229.483158)
		(end 286.039814 -229.095046)
		(width 0.18288)
		(layer "In6.Cu")
		(net "M_C_CPU0_SB_DQS_DN<0>")
	)
	(segment
		(start 293.20871 -232.282238)
		(end 292.820598 -231.894126)
		(width 0.18288)
		(layer "In6.Cu")
		(net "M_C_CPU0_SB_DQS_DN<0>")
	)
	(segment
		(start 339.666326 -242.62461)
		(end 339.65769 -242.619784)
		(width 0.088646)
		(layer "In6.Cu")
		(net "M_C_CPU0_SB_DQS_DN<0>")
	)
	(segment
		(start 291.813742 -231.264206)
		(end 291.306758 -231.054148)
		(width 0.18288)
		(layer "In6.Cu")
		(net "M_C_CPU0_SB_DQS_DN<0>")
	)
	(segment
		(start 302.306736 -233.712004)
		(end 302.182276 -233.587544)
		(width 0.18288)
		(layer "In6.Cu")
		(net "M_C_CPU0_SB_DQS_DN<0>")
	)
	(segment
		(start 313.442096 -236.845094)
		(end 312.647584 -236.050582)
		(width 0.18288)
		(layer "In6.Cu")
		(net "M_C_CPU0_SB_DQS_DN<0>")
	)
	(segment
		(start 339.091524 -242.619784)
		(end 339.083396 -242.62461)
		(width 0.088646)
		(layer "In6.Cu")
		(net "M_C_CPU0_SB_DQS_DN<0>")
	)
	(segment
		(start 282.959048 -228.59619)
		(end 282.544266 -228.181408)
		(width 0.18288)
		(layer "In6.Cu")
		(net "M_C_CPU0_SB_DQS_DN<0>")
	)
	(segment
		(start 310.143398 -235.439966)
		(end 309.594758 -235.439966)
		(width 0.18288)
		(layer "In6.Cu")
		(net "M_C_CPU0_SB_DQS_DN<0>")
	)
	(segment
		(start 309.470298 -235.315506)
		(end 308.921658 -235.315506)
		(width 0.18288)
		(layer "In6.Cu")
		(net "M_C_CPU0_SB_DQS_DN<0>")
	)
	(segment
		(start 342.438736 -242.473734)
		(end 342.165178 -242.473734)
		(width 0.088646)
		(layer "In6.Cu")
		(net "M_C_CPU0_SB_DQS_DN<0>")
	)
	(segment
		(start 340.986364 -242.61064)
		(end 340.971632 -242.619276)
		(width 0.088646)
		(layer "In6.Cu")
		(net "M_C_CPU0_SB_DQS_DN<0>")
	)
	(segment
		(start 331.944218 -241.76863)
		(end 331.36205 -241.186462)
		(width 0.088646)
		(layer "In6.Cu")
		(net "M_C_CPU0_SB_DQS_DN<0>")
	)
	(segment
		(start 298.781216 -233.441748)
		(end 298.526962 -233.696002)
		(width 0.18288)
		(layer "In6.Cu")
		(net "M_C_CPU0_SB_DQS_DN<0>")
	)
	(segment
		(start 342.664034 -242.294918)
		(end 342.632284 -242.410742)
		(width 0.088646)
		(layer "In6.Cu")
		(net "M_C_CPU0_SB_DQS_DN<0>")
	)
	(segment
		(start 305.61534 -234.316778)
		(end 305.49088 -234.441238)
		(width 0.18288)
		(layer "In6.Cu")
		(net "M_C_CPU0_SB_DQS_DN<0>")
	)
	(segment
		(start 292.387782 -231.637078)
		(end 291.881052 -231.42702)
		(width 0.18288)
		(layer "In6.Cu")
		(net "M_C_CPU0_SB_DQS_DN<0>")
	)
	(segment
		(start 281.169618 -227.919534)
		(end 280.55189 -228.175312)
		(width 0.18288)
		(layer "In6.Cu")
		(net "M_C_CPU0_SB_DQS_DN<0>")
	)
	(segment
		(start 337.21167 -242.619784)
		(end 337.199986 -242.626896)
		(width 0.088646)
		(layer "In6.Cu")
		(net "M_C_CPU0_SB_DQS_DN<0>")
	)
	(segment
		(start 296.816018 -232.736136)
		(end 296.267378 -232.736136)
		(width 0.18288)
		(layer "In6.Cu")
		(net "M_C_CPU0_SB_DQS_DN<0>")
	)
	(segment
		(start 301.509176 -233.712004)
		(end 300.960536 -233.712004)
		(width 0.18288)
		(layer "In6.Cu")
		(net "M_C_CPU0_SB_DQS_DN<0>")
	)
	(segment
		(start 300.960536 -233.712004)
		(end 300.836076 -233.587544)
		(width 0.18288)
		(layer "In6.Cu")
		(net "M_C_CPU0_SB_DQS_DN<0>")
	)
	(segment
		(start 293.20871 -232.45826)
		(end 293.20871 -232.282238)
		(width 0.18288)
		(layer "In6.Cu")
		(net "M_C_CPU0_SB_DQS_DN<0>")
	)
	(segment
		(start 301.633636 -233.587544)
		(end 301.509176 -233.712004)
		(width 0.18288)
		(layer "In6.Cu")
		(net "M_C_CPU0_SB_DQS_DN<0>")
	)
	(segment
		(start 284.455362 -228.602032)
		(end 284.195012 -228.341682)
		(width 0.18288)
		(layer "In6.Cu")
		(net "M_C_CPU0_SB_DQS_DN<0>")
	)
	(segment
		(start 300.836076 -233.587544)
		(end 300.287436 -233.587544)
		(width 0.18288)
		(layer "In6.Cu")
		(net "M_C_CPU0_SB_DQS_DN<0>")
	)
	(segment
		(start 291.881052 -231.42702)
		(end 291.813742 -231.264206)
		(width 0.18288)
		(layer "In6.Cu")
		(net "M_C_CPU0_SB_DQS_DN<0>")
	)
	(segment
		(start 285.370778 -228.602032)
		(end 284.455362 -228.602032)
		(width 0.18288)
		(layer "In6.Cu")
		(net "M_C_CPU0_SB_DQS_DN<0>")
	)
	(segment
		(start 306.83708 -234.441238)
		(end 306.28844 -234.441238)
		(width 0.18288)
		(layer "In6.Cu")
		(net "M_C_CPU0_SB_DQS_DN<0>")
	)
	(segment
		(start 305.49088 -234.441238)
		(end 304.94224 -234.441238)
		(width 0.18288)
		(layer "In6.Cu")
		(net "M_C_CPU0_SB_DQS_DN<0>")
	)
	(segment
		(start 315.073538 -236.845094)
		(end 313.442096 -236.845094)
		(width 0.18288)
		(layer "In6.Cu")
		(net "M_C_CPU0_SB_DQS_DN<0>")
	)
	(segment
		(start 293.596568 -232.846118)
		(end 293.20871 -232.45826)
		(width 0.18288)
		(layer "In6.Cu")
		(net "M_C_CPU0_SB_DQS_DN<0>")
	)
	(segment
		(start 331.36205 -241.186462)
		(end 331.112622 -241.186462)
		(width 0.088646)
		(layer "In6.Cu")
		(net "M_C_CPU0_SB_DQS_DN<0>")
	)
	(segment
		(start 304.26914 -234.316778)
		(end 304.14468 -234.441238)
		(width 0.18288)
		(layer "In6.Cu")
		(net "M_C_CPU0_SB_DQS_DN<0>")
	)
	(segment
		(start 283.69387 -228.341682)
		(end 283.439362 -228.59619)
		(width 0.18288)
		(layer "In6.Cu")
		(net "M_C_CPU0_SB_DQS_DN<0>")
	)
	(segment
		(start 294.398954 -232.846118)
		(end 293.596568 -232.846118)
		(width 0.18288)
		(layer "In6.Cu")
		(net "M_C_CPU0_SB_DQS_DN<0>")
	)
	(segment
		(start 304.14468 -234.441238)
		(end 303.58461 -234.441238)
		(width 0.18288)
		(layer "In6.Cu")
		(net "M_C_CPU0_SB_DQS_DN<0>")
	)
	(segment
		(start 292.644576 -231.894126)
		(end 292.387782 -231.637078)
		(width 0.18288)
		(layer "In6.Cu")
		(net "M_C_CPU0_SB_DQS_DN<0>")
	)
	(segment
		(start 338.15147 -242.619784)
		(end 338.139786 -242.626896)
		(width 0.088646)
		(layer "In6.Cu")
		(net "M_C_CPU0_SB_DQS_DN<0>")
	)
	(segment
		(start 291.143944 -231.121458)
		(end 290.604448 -230.897938)
		(width 0.18288)
		(layer "In6.Cu")
		(net "M_C_CPU0_SB_DQS_DN<0>")
	)
	(segment
		(start 306.28844 -234.441238)
		(end 306.16398 -234.316778)
		(width 0.18288)
		(layer "In6.Cu")
		(net "M_C_CPU0_SB_DQS_DN<0>")
	)
	(segment
		(start 307.835808 -235.439966)
		(end 306.83708 -234.441238)
		(width 0.18288)
		(layer "In6.Cu")
		(net "M_C_CPU0_SB_DQS_DN<0>")
	)
	(segment
		(start 286.815784 -230.047038)
		(end 286.427926 -229.65918)
		(width 0.18288)
		(layer "In6.Cu")
		(net "M_C_CPU0_SB_DQS_DN<0>")
	)
	(segment
		(start 294.653208 -232.591864)
		(end 294.398954 -232.846118)
		(width 0.18288)
		(layer "In6.Cu")
		(net "M_C_CPU0_SB_DQS_DN<0>")
	)
	(segment
		(start 336.27187 -242.619784)
		(end 336.263742 -242.62461)
		(width 0.088646)
		(layer "In6.Cu")
		(net "M_C_CPU0_SB_DQS_DN<0>")
	)
	(segment
		(start 280.075386 -228.175312)
		(end 279.816814 -227.91674)
		(width 0.18288)
		(layer "In6.Cu")
		(net "M_C_CPU0_SB_DQS_DN<0>")
	)
	(segment
		(start 285.863792 -229.095046)
		(end 285.370778 -228.602032)
		(width 0.18288)
		(layer "In6.Cu")
		(net "M_C_CPU0_SB_DQS_DN<0>")
	)
	(segment
		(start 332.060804 -242.560094)
		(end 331.944218 -242.443508)
		(width 0.088646)
		(layer "In6.Cu")
		(net "M_C_CPU0_SB_DQS_DN<0>")
	)
	(segment
		(start 288.032444 -230.047038)
		(end 286.815784 -230.047038)
		(width 0.18288)
		(layer "In6.Cu")
		(net "M_C_CPU0_SB_DQS_DN<0>")
	)
	(segment
		(start 331.112622 -241.186462)
		(end 331.052932 -241.126772)
		(width 0.088646)
		(layer "In6.Cu")
		(net "M_C_CPU0_SB_DQS_DN<0>")
	)
	(segment
		(start 311.614058 -236.050582)
		(end 310.143398 -235.439966)
		(width 0.18288)
		(layer "In6.Cu")
		(net "M_C_CPU0_SB_DQS_DN<0>")
	)
	(segment
		(start 308.797198 -235.439966)
		(end 307.835808 -235.439966)
		(width 0.18288)
		(layer "In6.Cu")
		(net "M_C_CPU0_SB_DQS_DN<0>")
	)
	(segment
		(start 341.53729 -242.619276)
		(end 341.537036 -242.619276)
		(width 0.088646)
		(layer "In6.Cu")
		(net "M_C_CPU0_SB_DQS_DN<0>")
	)
	(segment
		(start 292.820598 -231.894126)
		(end 292.644576 -231.894126)
		(width 0.18288)
		(layer "In6.Cu")
		(net "M_C_CPU0_SB_DQS_DN<0>")
	)
	(segment
		(start 299.282866 -233.441748)
		(end 298.781216 -233.441748)
		(width 0.18288)
		(layer "In6.Cu")
		(net "M_C_CPU0_SB_DQS_DN<0>")
	)
	(segment
		(start 334.958182 -242.619276)
		(end 334.947768 -242.61318)
		(width 0.088646)
		(layer "In6.Cu")
		(net "M_C_CPU0_SB_DQS_DN<0>")
	)
	(segment
		(start 295.42359 -232.860596)
		(end 295.154858 -232.591864)
		(width 0.18288)
		(layer "In6.Cu")
		(net "M_C_CPU0_SB_DQS_DN<0>")
	)
	(segment
		(start 302.855376 -233.712004)
		(end 302.306736 -233.712004)
		(width 0.18288)
		(layer "In6.Cu")
		(net "M_C_CPU0_SB_DQS_DN<0>")
	)
	(segment
		(start 303.58461 -234.441238)
		(end 302.855376 -233.712004)
		(width 0.18288)
		(layer "In6.Cu")
		(net "M_C_CPU0_SB_DQS_DN<0>")
	)
	(segment
		(start 331.944218 -242.443508)
		(end 331.944218 -241.76863)
		(width 0.088646)
		(layer "In6.Cu")
		(net "M_C_CPU0_SB_DQS_DN<0>")
	)
	(segment
		(start 296.267378 -232.736136)
		(end 296.142918 -232.860596)
		(width 0.18288)
		(layer "In6.Cu")
		(net "M_C_CPU0_SB_DQS_DN<0>")
	)
	(segment
		(start 302.182276 -233.587544)
		(end 301.633636 -233.587544)
		(width 0.18288)
		(layer "In6.Cu")
		(net "M_C_CPU0_SB_DQS_DN<0>")
	)
	(segment
		(start 284.195012 -228.341682)
		(end 283.69387 -228.341682)
		(width 0.18288)
		(layer "In6.Cu")
		(net "M_C_CPU0_SB_DQS_DN<0>")
	)
	(segment
		(start 333.078582 -242.619276)
		(end 333.06385 -242.61064)
		(width 0.088646)
		(layer "In6.Cu")
		(net "M_C_CPU0_SB_DQS_DN<0>")
	)
	(segment
		(start 298.211748 -233.696002)
		(end 297.376342 -232.860596)
		(width 0.18288)
		(layer "In6.Cu")
		(net "M_C_CPU0_SB_DQS_DN<0>")
	)
	(segment
		(start 304.94224 -234.441238)
		(end 304.81778 -234.316778)
		(width 0.18288)
		(layer "In6.Cu")
		(net "M_C_CPU0_SB_DQS_DN<0>")
	)
	(segment
		(start 341.91194 -242.61953)
		(end 341.911686 -242.619276)
		(width 0.088646)
		(layer "In6.Cu")
		(net "M_C_CPU0_SB_DQS_DN<0>")
	)
	(segment
		(start 296.142918 -232.860596)
		(end 295.42359 -232.860596)
		(width 0.18288)
		(layer "In6.Cu")
		(net "M_C_CPU0_SB_DQS_DN<0>")
	)
	(segment
		(start 300.287436 -233.587544)
		(end 300.162976 -233.712004)
		(width 0.18288)
		(layer "In6.Cu")
		(net "M_C_CPU0_SB_DQS_DN<0>")
	)
	(segment
		(start 340.046564 -242.61064)
		(end 340.031832 -242.619276)
		(width 0.088646)
		(layer "In6.Cu")
		(net "M_C_CPU0_SB_DQS_DN<0>")
	)
	(segment
		(start 280.55189 -228.175312)
		(end 280.075386 -228.175312)
		(width 0.18288)
		(layer "In6.Cu")
		(net "M_C_CPU0_SB_DQS_DN<0>")
	)
	(segment
		(start 331.029564 -241.126772)
		(end 319.355216 -241.126772)
		(width 0.18288)
		(layer "In6.Cu")
		(net "M_C_CPU0_SB_DQS_DN<0>")
	)
	(segment
		(start 308.921658 -235.315506)
		(end 308.797198 -235.439966)
		(width 0.18288)
		(layer "In6.Cu")
		(net "M_C_CPU0_SB_DQS_DN<0>")
	)
	(segment
		(start 291.306758 -231.054148)
		(end 291.143944 -231.121458)
		(width 0.18288)
		(layer "In6.Cu")
		(net "M_C_CPU0_SB_DQS_DN<0>")
	)
	(segment
		(start 282.544266 -228.181408)
		(end 281.91206 -227.919534)
		(width 0.18288)
		(layer "In6.Cu")
		(net "M_C_CPU0_SB_DQS_DN<0>")
	)
	(segment
		(start 295.154858 -232.591864)
		(end 294.653208 -232.591864)
		(width 0.18288)
		(layer "In6.Cu")
		(net "M_C_CPU0_SB_DQS_DN<0>")
	)
	(segment
		(start 296.940478 -232.860596)
		(end 296.816018 -232.736136)
		(width 0.18288)
		(layer "In6.Cu")
		(net "M_C_CPU0_SB_DQS_DN<0>")
	)
	(segment
		(start 334.018636 -242.619276)
		(end 334.008222 -242.61318)
		(width 0.088646)
		(layer "In6.Cu")
		(net "M_C_CPU0_SB_DQS_DN<0>")
	)
	(segment
		(start 297.376342 -232.860596)
		(end 296.940478 -232.860596)
		(width 0.18288)
		(layer "In6.Cu")
		(net "M_C_CPU0_SB_DQS_DN<0>")
	)
	(segment
		(start 306.16398 -234.316778)
		(end 305.61534 -234.316778)
		(width 0.18288)
		(layer "In6.Cu")
		(net "M_C_CPU0_SB_DQS_DN<0>")
	)
	(segment
		(start 281.91206 -227.919534)
		(end 281.169618 -227.919534)
		(width 0.18288)
		(layer "In6.Cu")
		(net "M_C_CPU0_SB_DQS_DN<0>")
	)
	(segment
		(start 288.883344 -230.897938)
		(end 288.032444 -230.047038)
		(width 0.18288)
		(layer "In6.Cu")
		(net "M_C_CPU0_SB_DQS_DN<0>")
	)
	(segment
		(start 342.632284 -242.410742)
		(end 342.593422 -242.43284)
		(width 0.088646)
		(layer "In6.Cu")
		(net "M_C_CPU0_SB_DQS_DN<0>")
	)
	(segment
		(start 319.355216 -241.126772)
		(end 315.073538 -236.845094)
		(width 0.18288)
		(layer "In6.Cu")
		(net "M_C_CPU0_SB_DQS_DN<0>")
	)
	(segment
		(start 331.052932 -241.126772)
		(end 331.029564 -241.126772)
		(width 0.088646)
		(layer "In6.Cu")
		(net "M_C_CPU0_SB_DQS_DN<0>")
	)
	(segment
		(start 340.031832 -242.619276)
		(end 340.031832 -242.61953)
		(width 0.088646)
		(layer "In6.Cu")
		(net "M_C_CPU0_SB_DQS_DN<0>")
	)
	(segment
		(start 286.039814 -229.095046)
		(end 285.863792 -229.095046)
		(width 0.18288)
		(layer "In6.Cu")
		(net "M_C_CPU0_SB_DQS_DN<0>")
	)
	(segment
		(start 309.594758 -235.439966)
		(end 309.470298 -235.315506)
		(width 0.18288)
		(layer "In6.Cu")
		(net "M_C_CPU0_SB_DQS_DN<0>")
	)
	(segment
		(start 304.81778 -234.316778)
		(end 304.26914 -234.316778)
		(width 0.18288)
		(layer "In6.Cu")
		(net "M_C_CPU0_SB_DQS_DN<0>")
	)
	(segment
		(start 312.647584 -236.050582)
		(end 311.614058 -236.050582)
		(width 0.18288)
		(layer "In6.Cu")
		(net "M_C_CPU0_SB_DQS_DN<0>")
	)
	(segment
		(start 342.165178 -242.473734)
		(end 341.91194 -242.61953)
		(width 0.088646)
		(layer "In6.Cu")
		(net "M_C_CPU0_SB_DQS_DN<0>")
	)
	(arc
		(start 338.139786 -242.626896)
		(mid 337.957726 -242.669916)
		(end 337.777582 -242.61953)
		(width 0.088646)
		(layer "In6.Cu")
		(net "M_C_CPU0_SB_DQS_DN<0>")
	)
	(arc
		(start 332.513178 -242.619276)
		(mid 332.32598 -242.669419)
		(end 332.138782 -242.619276)
		(width 0.088646)
		(layer "In6.Cu")
		(net "M_C_CPU0_SB_DQS_DN<0>")
	)
	(arc
		(start 337.199986 -242.626896)
		(mid 337.017926 -242.669916)
		(end 336.837782 -242.61953)
		(width 0.088646)
		(layer "In6.Cu")
		(net "M_C_CPU0_SB_DQS_DN<0>")
	)
	(arc
		(start 335.89849 -242.619276)
		(mid 335.615534 -242.543407)
		(end 335.332578 -242.619276)
		(width 0.088646)
		(layer "In6.Cu")
		(net "M_C_CPU0_SB_DQS_DN<0>")
	)
	(arc
		(start 341.911686 -242.619276)
		(mid 341.724488 -242.669419)
		(end 341.53729 -242.619276)
		(width 0.088646)
		(layer "In6.Cu")
		(net "M_C_CPU0_SB_DQS_DN<0>")
	)
	(arc
		(start 334.393032 -242.619276)
		(mid 334.205834 -242.669419)
		(end 334.018636 -242.619276)
		(width 0.088646)
		(layer "In6.Cu")
		(net "M_C_CPU0_SB_DQS_DN<0>")
	)
	(arc
		(start 334.008222 -242.61318)
		(mid 333.72979 -242.543366)
		(end 333.452978 -242.619276)
		(width 0.088646)
		(layer "In6.Cu")
		(net "M_C_CPU0_SB_DQS_DN<0>")
	)
	(arc
		(start 333.06385 -242.61064)
		(mid 332.787409 -242.543474)
		(end 332.513178 -242.619276)
		(width 0.088646)
		(layer "In6.Cu")
		(net "M_C_CPU0_SB_DQS_DN<0>")
	)
	(arc
		(start 339.65769 -242.619784)
		(mid 339.374624 -242.543847)
		(end 339.091524 -242.619784)
		(width 0.088646)
		(layer "In6.Cu")
		(net "M_C_CPU0_SB_DQS_DN<0>")
	)
	(arc
		(start 335.332578 -242.619276)
		(mid 335.14538 -242.669419)
		(end 334.958182 -242.619276)
		(width 0.088646)
		(layer "In6.Cu")
		(net "M_C_CPU0_SB_DQS_DN<0>")
	)
	(arc
		(start 339.083396 -242.62461)
		(mid 338.899604 -242.669854)
		(end 338.717128 -242.61953)
		(width 0.088646)
		(layer "In6.Cu")
		(net "M_C_CPU0_SB_DQS_DN<0>")
	)
	(arc
		(start 341.537036 -242.619276)
		(mid 341.262807 -242.543351)
		(end 340.986364 -242.61064)
		(width 0.088646)
		(layer "In6.Cu")
		(net "M_C_CPU0_SB_DQS_DN<0>")
	)
	(arc
		(start 337.777582 -242.61953)
		(mid 337.494597 -242.543754)
		(end 337.21167 -242.619784)
		(width 0.088646)
		(layer "In6.Cu")
		(net "M_C_CPU0_SB_DQS_DN<0>")
	)
	(arc
		(start 336.837782 -242.61953)
		(mid 336.554797 -242.543754)
		(end 336.27187 -242.619784)
		(width 0.088646)
		(layer "In6.Cu")
		(net "M_C_CPU0_SB_DQS_DN<0>")
	)
	(arc
		(start 334.947768 -242.61318)
		(mid 334.66959 -242.543488)
		(end 334.393032 -242.619276)
		(width 0.088646)
		(layer "In6.Cu")
		(net "M_C_CPU0_SB_DQS_DN<0>")
	)
	(arc
		(start 333.452978 -242.619276)
		(mid 333.26578 -242.669419)
		(end 333.078582 -242.619276)
		(width 0.088646)
		(layer "In6.Cu")
		(net "M_C_CPU0_SB_DQS_DN<0>")
	)
	(arc
		(start 338.717128 -242.61953)
		(mid 338.434252 -242.543754)
		(end 338.15147 -242.619784)
		(width 0.088646)
		(layer "In6.Cu")
		(net "M_C_CPU0_SB_DQS_DN<0>")
	)
	(arc
		(start 332.138782 -242.619276)
		(mid 332.097852 -242.592243)
		(end 332.060804 -242.560094)
		(width 0.088646)
		(layer "In6.Cu")
		(net "M_C_CPU0_SB_DQS_DN<0>")
	)
	(arc
		(start 336.263742 -242.62461)
		(mid 336.080204 -242.669733)
		(end 335.897982 -242.61953)
		(width 0.088646)
		(layer "In6.Cu")
		(net "M_C_CPU0_SB_DQS_DN<0>")
	)
	(arc
		(start 340.971632 -242.619276)
		(mid 340.784434 -242.669419)
		(end 340.597236 -242.619276)
		(width 0.088646)
		(layer "In6.Cu")
		(net "M_C_CPU0_SB_DQS_DN<0>")
	)
	(arc
		(start 340.597236 -242.619276)
		(mid 340.323007 -242.543351)
		(end 340.046564 -242.61064)
		(width 0.088646)
		(layer "In6.Cu")
		(net "M_C_CPU0_SB_DQS_DN<0>")
	)
	(arc
		(start 340.031832 -242.61953)
		(mid 339.849753 -242.669638)
		(end 339.666326 -242.62461)
		(width 0.088646)
		(layer "In6.Cu")
		(net "M_C_CPU0_SB_DQS_DN<0>")
	)
	(arc
		(start 342.593422 -242.43284)
		(mid 342.518737 -242.463345)
		(end 342.438736 -242.473734)
		(width 0.088646)
		(layer "In6.Cu")
		(net "M_C_CPU0_SB_DQS_DN<0>")
	)
	(segment
		(start 276.469094 -220.69171)
		(end 276.138386 -220.69171)
		(width 0.101854)
		(layer "F.Cu")
		(net "M_C_CPU0_SB_DQ<9>")
	)
	(segment
		(start 276.138386 -220.69171)
		(end 274.152868 -220.69171)
		(width 0.1016)
		(layer "F.Cu")
		(net "M_C_CPU0_SB_DQ<9>")
	)
	(segment
		(start 273.53514 -220.68282)
		(end 273.37258 -220.84538)
		(width 0.20066)
		(layer "F.Cu")
		(net "M_C_CPU0_SB_DQ<9>")
	)
	(segment
		(start 273.37258 -220.84538)
		(end 273.37258 -221.173548)
		(width 0.20066)
		(layer "F.Cu")
		(net "M_C_CPU0_SB_DQ<9>")
	)
	(segment
		(start 274.143978 -220.68282)
		(end 273.53514 -220.68282)
		(width 0.20066)
		(layer "F.Cu")
		(net "M_C_CPU0_SB_DQ<9>")
	)
	(segment
		(start 272.713704 -221.32798)
		(end 272.502376 -221.116652)
		(width 0.20066)
		(layer "F.Cu")
		(net "M_C_CPU0_SB_DQ<9>")
	)
	(segment
		(start 277.072598 -221.116652)
		(end 276.647656 -220.69171)
		(width 0.20066)
		(layer "F.Cu")
		(net "M_C_CPU0_SB_DQ<9>")
	)
	(segment
		(start 279.816814 -221.116652)
		(end 278.711914 -221.116652)
		(width 0.20066)
		(layer "F.Cu")
		(net "M_C_CPU0_SB_DQ<9>")
	)
	(segment
		(start 272.502376 -221.116652)
		(end 271.168114 -221.116652)
		(width 0.20066)
		(layer "F.Cu")
		(net "M_C_CPU0_SB_DQ<9>")
	)
	(segment
		(start 278.711914 -221.116652)
		(end 277.072598 -221.116652)
		(width 0.20066)
		(layer "F.Cu")
		(net "M_C_CPU0_SB_DQ<9>")
	)
	(segment
		(start 276.647656 -220.69171)
		(end 276.469094 -220.69171)
		(width 0.20066)
		(layer "F.Cu")
		(net "M_C_CPU0_SB_DQ<9>")
	)
	(segment
		(start 343.133934 -238.761524)
		(end 343.13368 -238.76127)
		(width 0.20066)
		(layer "F.Cu")
		(net "M_C_CPU0_SB_DQ<9>")
	)
	(segment
		(start 343.13368 -238.76127)
		(end 343.13368 -238.225584)
		(width 0.20066)
		(layer "F.Cu")
		(net "M_C_CPU0_SB_DQ<9>")
	)
	(segment
		(start 273.218148 -221.32798)
		(end 272.713704 -221.32798)
		(width 0.20066)
		(layer "F.Cu")
		(net "M_C_CPU0_SB_DQ<9>")
	)
	(segment
		(start 273.37258 -221.173548)
		(end 273.218148 -221.32798)
		(width 0.20066)
		(layer "F.Cu")
		(net "M_C_CPU0_SB_DQ<9>")
	)
	(segment
		(start 274.152868 -220.69171)
		(end 274.143978 -220.68282)
		(width 0.1016)
		(layer "F.Cu")
		(net "M_C_CPU0_SB_DQ<9>")
	)
	(segment
		(start 281.298396 -221.541594)
		(end 281.115516 -221.724474)
		(width 0.18288)
		(layer "In6.Cu")
		(net "M_C_CPU0_SB_DQ<9>")
	)
	(segment
		(start 281.115516 -221.724474)
		(end 281.115516 -222.297244)
		(width 0.18288)
		(layer "In6.Cu")
		(net "M_C_CPU0_SB_DQ<9>")
	)
	(segment
		(start 288.985452 -222.180404)
		(end 288.106104 -221.301056)
		(width 0.18288)
		(layer "In6.Cu")
		(net "M_C_CPU0_SB_DQ<9>")
	)
	(segment
		(start 293.925752 -224.0915)
		(end 293.075614 -223.241362)
		(width 0.18288)
		(layer "In6.Cu")
		(net "M_C_CPU0_SB_DQ<9>")
	)
	(segment
		(start 330.775564 -236.511592)
		(end 321.59829 -236.511592)
		(width 0.18288)
		(layer "In6.Cu")
		(net "M_C_CPU0_SB_DQ<9>")
	)
	(segment
		(start 284.852364 -221.301056)
		(end 284.611826 -221.541594)
		(width 0.18288)
		(layer "In6.Cu")
		(net "M_C_CPU0_SB_DQ<9>")
	)
	(segment
		(start 280.424636 -222.297244)
		(end 280.424636 -221.724474)
		(width 0.18288)
		(layer "In6.Cu")
		(net "M_C_CPU0_SB_DQ<9>")
	)
	(segment
		(start 332.983332 -237.901226)
		(end 332.971394 -237.894368)
		(width 0.088646)
		(layer "In6.Cu")
		(net "M_C_CPU0_SB_DQ<9>")
	)
	(segment
		(start 333.171038 -238.241078)
		(end 333.171038 -238.225584)
		(width 0.088646)
		(layer "In6.Cu")
		(net "M_C_CPU0_SB_DQ<9>")
	)
	(segment
		(start 310.435752 -225.791522)
		(end 306.976018 -225.791522)
		(width 0.18288)
		(layer "In6.Cu")
		(net "M_C_CPU0_SB_DQ<9>")
	)
	(segment
		(start 312.358532 -227.58654)
		(end 311.615328 -227.58654)
		(width 0.18288)
		(layer "In6.Cu")
		(net "M_C_CPU0_SB_DQ<9>")
	)
	(segment
		(start 306.976018 -225.791522)
		(end 306.192428 -225.007932)
		(width 0.18288)
		(layer "In6.Cu")
		(net "M_C_CPU0_SB_DQ<9>")
	)
	(segment
		(start 282.311602 -220.274896)
		(end 282.311602 -221.358714)
		(width 0.18288)
		(layer "In6.Cu")
		(net "M_C_CPU0_SB_DQ<9>")
	)
	(segment
		(start 280.424636 -221.724474)
		(end 279.816814 -221.116652)
		(width 0.18288)
		(layer "In6.Cu")
		(net "M_C_CPU0_SB_DQ<9>")
	)
	(segment
		(start 313.07151 -228.75494)
		(end 313.07151 -228.299518)
		(width 0.18288)
		(layer "In6.Cu")
		(net "M_C_CPU0_SB_DQ<9>")
	)
	(segment
		(start 310.753506 -226.109276)
		(end 310.435752 -225.791522)
		(width 0.18288)
		(layer "In6.Cu")
		(net "M_C_CPU0_SB_DQ<9>")
	)
	(segment
		(start 288.106104 -221.301056)
		(end 284.852364 -221.301056)
		(width 0.18288)
		(layer "In6.Cu")
		(net "M_C_CPU0_SB_DQ<9>")
	)
	(segment
		(start 283.002482 -220.274896)
		(end 282.819602 -220.092016)
		(width 0.18288)
		(layer "In6.Cu")
		(net "M_C_CPU0_SB_DQ<9>")
	)
	(segment
		(start 331.039724 -236.600238)
		(end 330.951078 -236.511592)
		(width 0.088646)
		(layer "In6.Cu")
		(net "M_C_CPU0_SB_DQ<9>")
	)
	(segment
		(start 338.166964 -238.723678)
		(end 338.152232 -238.715042)
		(width 0.088646)
		(layer "In6.Cu")
		(net "M_C_CPU0_SB_DQ<9>")
	)
	(segment
		(start 280.607516 -222.480124)
		(end 280.424636 -222.297244)
		(width 0.18288)
		(layer "In6.Cu")
		(net "M_C_CPU0_SB_DQ<9>")
	)
	(segment
		(start 281.115516 -222.297244)
		(end 280.932636 -222.480124)
		(width 0.18288)
		(layer "In6.Cu")
		(net "M_C_CPU0_SB_DQ<9>")
	)
	(segment
		(start 334.018636 -238.715042)
		(end 334.003904 -238.723678)
		(width 0.088646)
		(layer "In6.Cu")
		(net "M_C_CPU0_SB_DQ<9>")
	)
	(segment
		(start 297.976798 -224.941384)
		(end 297.126914 -224.0915)
		(width 0.18288)
		(layer "In6.Cu")
		(net "M_C_CPU0_SB_DQ<9>")
	)
	(segment
		(start 304.075846 -225.007932)
		(end 303.77257 -224.704656)
		(width 0.18288)
		(layer "In6.Cu")
		(net "M_C_CPU0_SB_DQ<9>")
	)
	(segment
		(start 340.986364 -238.723678)
		(end 340.971632 -238.715042)
		(width 0.088646)
		(layer "In6.Cu")
		(net "M_C_CPU0_SB_DQ<9>")
	)
	(segment
		(start 336.287364 -238.723678)
		(end 336.272632 -238.715042)
		(width 0.088646)
		(layer "In6.Cu")
		(net "M_C_CPU0_SB_DQ<9>")
	)
	(segment
		(start 311.615328 -227.58654)
		(end 310.753506 -226.724718)
		(width 0.18288)
		(layer "In6.Cu")
		(net "M_C_CPU0_SB_DQ<9>")
	)
	(segment
		(start 299.896022 -224.704656)
		(end 299.659294 -224.941384)
		(width 0.18288)
		(layer "In6.Cu")
		(net "M_C_CPU0_SB_DQ<9>")
	)
	(segment
		(start 282.128722 -221.541594)
		(end 281.298396 -221.541594)
		(width 0.18288)
		(layer "In6.Cu")
		(net "M_C_CPU0_SB_DQ<9>")
	)
	(segment
		(start 283.002482 -221.358714)
		(end 283.002482 -220.274896)
		(width 0.18288)
		(layer "In6.Cu")
		(net "M_C_CPU0_SB_DQ<9>")
	)
	(segment
		(start 341.921846 -238.721138)
		(end 341.911432 -238.715042)
		(width 0.088646)
		(layer "In6.Cu")
		(net "M_C_CPU0_SB_DQ<9>")
	)
	(segment
		(start 282.494482 -220.092016)
		(end 282.311602 -220.274896)
		(width 0.18288)
		(layer "In6.Cu")
		(net "M_C_CPU0_SB_DQ<9>")
	)
	(segment
		(start 334.958436 -238.715042)
		(end 334.943704 -238.723678)
		(width 0.088646)
		(layer "In6.Cu")
		(net "M_C_CPU0_SB_DQ<9>")
	)
	(segment
		(start 332.32598 -237.977172)
		(end 331.752702 -237.977172)
		(width 0.088646)
		(layer "In6.Cu")
		(net "M_C_CPU0_SB_DQ<9>")
	)
	(segment
		(start 289.36696 -222.180404)
		(end 288.985452 -222.180404)
		(width 0.18288)
		(layer "In6.Cu")
		(net "M_C_CPU0_SB_DQ<9>")
	)
	(segment
		(start 299.659294 -224.941384)
		(end 297.976798 -224.941384)
		(width 0.18288)
		(layer "In6.Cu")
		(net "M_C_CPU0_SB_DQ<9>")
	)
	(segment
		(start 293.075614 -223.241362)
		(end 290.427918 -223.241362)
		(width 0.18288)
		(layer "In6.Cu")
		(net "M_C_CPU0_SB_DQ<9>")
	)
	(segment
		(start 337.227164 -238.723678)
		(end 337.212432 -238.715042)
		(width 0.088646)
		(layer "In6.Cu")
		(net "M_C_CPU0_SB_DQ<9>")
	)
	(segment
		(start 297.126914 -224.0915)
		(end 293.925752 -224.0915)
		(width 0.18288)
		(layer "In6.Cu")
		(net "M_C_CPU0_SB_DQ<9>")
	)
	(segment
		(start 284.611826 -221.541594)
		(end 283.185362 -221.541594)
		(width 0.18288)
		(layer "In6.Cu")
		(net "M_C_CPU0_SB_DQ<9>")
	)
	(segment
		(start 282.311602 -221.358714)
		(end 282.128722 -221.541594)
		(width 0.18288)
		(layer "In6.Cu")
		(net "M_C_CPU0_SB_DQ<9>")
	)
	(segment
		(start 331.039724 -236.811312)
		(end 331.039724 -236.600238)
		(width 0.088646)
		(layer "In6.Cu")
		(net "M_C_CPU0_SB_DQ<9>")
	)
	(segment
		(start 331.511148 -237.735618)
		(end 331.511148 -237.282736)
		(width 0.088646)
		(layer "In6.Cu")
		(net "M_C_CPU0_SB_DQ<9>")
	)
	(segment
		(start 306.192428 -225.007932)
		(end 304.075846 -225.007932)
		(width 0.18288)
		(layer "In6.Cu")
		(net "M_C_CPU0_SB_DQ<9>")
	)
	(segment
		(start 332.995778 -237.908338)
		(end 332.983332 -237.901226)
		(width 0.088646)
		(layer "In6.Cu")
		(net "M_C_CPU0_SB_DQ<9>")
	)
	(segment
		(start 303.77257 -224.704656)
		(end 299.896022 -224.704656)
		(width 0.18288)
		(layer "In6.Cu")
		(net "M_C_CPU0_SB_DQ<9>")
	)
	(segment
		(start 280.932636 -222.480124)
		(end 280.607516 -222.480124)
		(width 0.18288)
		(layer "In6.Cu")
		(net "M_C_CPU0_SB_DQ<9>")
	)
	(segment
		(start 313.51093 -229.19436)
		(end 313.07151 -228.75494)
		(width 0.18288)
		(layer "In6.Cu")
		(net "M_C_CPU0_SB_DQ<9>")
	)
	(segment
		(start 310.753506 -226.724718)
		(end 310.753506 -226.109276)
		(width 0.18288)
		(layer "In6.Cu")
		(net "M_C_CPU0_SB_DQ<9>")
	)
	(segment
		(start 330.951078 -236.511592)
		(end 330.775564 -236.511592)
		(width 0.088646)
		(layer "In6.Cu")
		(net "M_C_CPU0_SB_DQ<9>")
	)
	(segment
		(start 290.427918 -223.241362)
		(end 289.36696 -222.180404)
		(width 0.18288)
		(layer "In6.Cu")
		(net "M_C_CPU0_SB_DQ<9>")
	)
	(segment
		(start 314.281058 -229.19436)
		(end 313.51093 -229.19436)
		(width 0.18288)
		(layer "In6.Cu")
		(net "M_C_CPU0_SB_DQ<9>")
	)
	(segment
		(start 321.59829 -236.511592)
		(end 314.281058 -229.19436)
		(width 0.18288)
		(layer "In6.Cu")
		(net "M_C_CPU0_SB_DQ<9>")
	)
	(segment
		(start 283.185362 -221.541594)
		(end 283.002482 -221.358714)
		(width 0.18288)
		(layer "In6.Cu")
		(net "M_C_CPU0_SB_DQ<9>")
	)
	(segment
		(start 282.819602 -220.092016)
		(end 282.494482 -220.092016)
		(width 0.18288)
		(layer "In6.Cu")
		(net "M_C_CPU0_SB_DQ<9>")
	)
	(segment
		(start 331.511148 -237.282736)
		(end 331.039724 -236.811312)
		(width 0.088646)
		(layer "In6.Cu")
		(net "M_C_CPU0_SB_DQ<9>")
	)
	(segment
		(start 331.752702 -237.977172)
		(end 331.511148 -237.735618)
		(width 0.088646)
		(layer "In6.Cu")
		(net "M_C_CPU0_SB_DQ<9>")
	)
	(segment
		(start 313.07151 -228.299518)
		(end 312.358532 -227.58654)
		(width 0.18288)
		(layer "In6.Cu")
		(net "M_C_CPU0_SB_DQ<9>")
	)
	(segment
		(start 340.046564 -238.723678)
		(end 340.031832 -238.715042)
		(width 0.088646)
		(layer "In6.Cu")
		(net "M_C_CPU0_SB_DQ<9>")
	)
	(arc
		(start 341.537036 -238.715042)
		(mid 341.262837 -238.790877)
		(end 340.986364 -238.723678)
		(width 0.088646)
		(layer "In6.Cu")
		(net "M_C_CPU0_SB_DQ<9>")
	)
	(arc
		(start 339.092032 -238.715042)
		(mid 338.904834 -238.664899)
		(end 338.717636 -238.715042)
		(width 0.088646)
		(layer "In6.Cu")
		(net "M_C_CPU0_SB_DQ<9>")
	)
	(arc
		(start 332.608936 -237.901226)
		(mid 332.472464 -237.957849)
		(end 332.32598 -237.977172)
		(width 0.088646)
		(layer "In6.Cu")
		(net "M_C_CPU0_SB_DQ<9>")
	)
	(arc
		(start 334.943704 -238.723678)
		(mid 334.667229 -238.790998)
		(end 334.393032 -238.715042)
		(width 0.088646)
		(layer "In6.Cu")
		(net "M_C_CPU0_SB_DQ<9>")
	)
	(arc
		(start 335.332832 -238.715042)
		(mid 335.145634 -238.664899)
		(end 334.958436 -238.715042)
		(width 0.088646)
		(layer "In6.Cu")
		(net "M_C_CPU0_SB_DQ<9>")
	)
	(arc
		(start 338.717636 -238.715042)
		(mid 338.443437 -238.790877)
		(end 338.166964 -238.723678)
		(width 0.088646)
		(layer "In6.Cu")
		(net "M_C_CPU0_SB_DQ<9>")
	)
	(arc
		(start 336.838036 -238.715042)
		(mid 336.563837 -238.790877)
		(end 336.287364 -238.723678)
		(width 0.088646)
		(layer "In6.Cu")
		(net "M_C_CPU0_SB_DQ<9>")
	)
	(arc
		(start 339.657436 -238.715042)
		(mid 339.374734 -238.790818)
		(end 339.092032 -238.715042)
		(width 0.088646)
		(layer "In6.Cu")
		(net "M_C_CPU0_SB_DQ<9>")
	)
	(arc
		(start 340.597236 -238.715042)
		(mid 340.323037 -238.790877)
		(end 340.046564 -238.723678)
		(width 0.088646)
		(layer "In6.Cu")
		(net "M_C_CPU0_SB_DQ<9>")
	)
	(arc
		(start 341.911432 -238.715042)
		(mid 341.724234 -238.664899)
		(end 341.537036 -238.715042)
		(width 0.088646)
		(layer "In6.Cu")
		(net "M_C_CPU0_SB_DQ<9>")
	)
	(arc
		(start 335.898236 -238.715042)
		(mid 335.615534 -238.790818)
		(end 335.332832 -238.715042)
		(width 0.088646)
		(layer "In6.Cu")
		(net "M_C_CPU0_SB_DQ<9>")
	)
	(arc
		(start 336.272632 -238.715042)
		(mid 336.085434 -238.664899)
		(end 335.898236 -238.715042)
		(width 0.088646)
		(layer "In6.Cu")
		(net "M_C_CPU0_SB_DQ<9>")
	)
	(arc
		(start 337.212432 -238.715042)
		(mid 337.025234 -238.664899)
		(end 336.838036 -238.715042)
		(width 0.088646)
		(layer "In6.Cu")
		(net "M_C_CPU0_SB_DQ<9>")
	)
	(arc
		(start 332.971394 -237.894368)
		(mid 332.789283 -237.851043)
		(end 332.608936 -237.901226)
		(width 0.088646)
		(layer "In6.Cu")
		(net "M_C_CPU0_SB_DQ<9>")
	)
	(arc
		(start 338.152232 -238.715042)
		(mid 337.965034 -238.664899)
		(end 337.777836 -238.715042)
		(width 0.088646)
		(layer "In6.Cu")
		(net "M_C_CPU0_SB_DQ<9>")
	)
	(arc
		(start 334.003904 -238.723678)
		(mid 333.727429 -238.790998)
		(end 333.453232 -238.715042)
		(width 0.088646)
		(layer "In6.Cu")
		(net "M_C_CPU0_SB_DQ<9>")
	)
	(arc
		(start 333.453232 -238.715042)
		(mid 333.250409 -238.514811)
		(end 333.171038 -238.241078)
		(width 0.088646)
		(layer "In6.Cu")
		(net "M_C_CPU0_SB_DQ<9>")
	)
	(arc
		(start 334.393032 -238.715042)
		(mid 334.205834 -238.664899)
		(end 334.018636 -238.715042)
		(width 0.088646)
		(layer "In6.Cu")
		(net "M_C_CPU0_SB_DQ<9>")
	)
	(arc
		(start 343.13368 -238.225584)
		(mid 342.819398 -238.489468)
		(end 342.476582 -238.715042)
		(width 0.088646)
		(layer "In6.Cu")
		(net "M_C_CPU0_SB_DQ<9>")
	)
	(arc
		(start 342.476582 -238.715042)
		(mid 342.200023 -238.790785)
		(end 341.921846 -238.721138)
		(width 0.088646)
		(layer "In6.Cu")
		(net "M_C_CPU0_SB_DQ<9>")
	)
	(arc
		(start 333.171038 -238.225584)
		(mid 333.124301 -238.044378)
		(end 332.995778 -237.908338)
		(width 0.088646)
		(layer "In6.Cu")
		(net "M_C_CPU0_SB_DQ<9>")
	)
	(arc
		(start 340.971632 -238.715042)
		(mid 340.784434 -238.664899)
		(end 340.597236 -238.715042)
		(width 0.088646)
		(layer "In6.Cu")
		(net "M_C_CPU0_SB_DQ<9>")
	)
	(arc
		(start 340.031832 -238.715042)
		(mid 339.844634 -238.664899)
		(end 339.657436 -238.715042)
		(width 0.088646)
		(layer "In6.Cu")
		(net "M_C_CPU0_SB_DQ<9>")
	)
	(arc
		(start 337.777836 -238.715042)
		(mid 337.503637 -238.790877)
		(end 337.227164 -238.723678)
		(width 0.088646)
		(layer "In6.Cu")
		(net "M_C_CPU0_SB_DQ<9>")
	)
	(segment
		(start 279.816814 -222.816674)
		(end 278.711914 -222.816674)
		(width 0.20066)
		(layer "F.Cu")
		(net "M_C_CPU0_SB_DQ<8>")
	)
	(segment
		(start 272.741136 -223.055434)
		(end 272.502376 -222.816674)
		(width 0.20066)
		(layer "F.Cu")
		(net "M_C_CPU0_SB_DQ<8>")
	)
	(segment
		(start 274.143978 -222.383604)
		(end 273.58213 -222.383604)
		(width 0.20066)
		(layer "F.Cu")
		(net "M_C_CPU0_SB_DQ<8>")
	)
	(segment
		(start 276.917912 -222.391732)
		(end 276.469094 -222.391732)
		(width 0.20066)
		(layer "F.Cu")
		(net "M_C_CPU0_SB_DQ<8>")
	)
	(segment
		(start 273.37258 -222.882714)
		(end 273.19986 -223.055434)
		(width 0.20066)
		(layer "F.Cu")
		(net "M_C_CPU0_SB_DQ<8>")
	)
	(segment
		(start 274.40001 -222.391732)
		(end 274.152106 -222.391732)
		(width 0.101854)
		(layer "F.Cu")
		(net "M_C_CPU0_SB_DQ<8>")
	)
	(segment
		(start 277.342854 -222.816674)
		(end 276.917912 -222.391732)
		(width 0.20066)
		(layer "F.Cu")
		(net "M_C_CPU0_SB_DQ<8>")
	)
	(segment
		(start 273.19986 -223.055434)
		(end 272.741136 -223.055434)
		(width 0.20066)
		(layer "F.Cu")
		(net "M_C_CPU0_SB_DQ<8>")
	)
	(segment
		(start 278.711914 -222.816674)
		(end 277.342854 -222.816674)
		(width 0.20066)
		(layer "F.Cu")
		(net "M_C_CPU0_SB_DQ<8>")
	)
	(segment
		(start 273.58213 -222.383604)
		(end 273.37258 -222.593154)
		(width 0.20066)
		(layer "F.Cu")
		(net "M_C_CPU0_SB_DQ<8>")
	)
	(segment
		(start 274.152106 -222.391732)
		(end 274.143978 -222.383604)
		(width 0.101854)
		(layer "F.Cu")
		(net "M_C_CPU0_SB_DQ<8>")
	)
	(segment
		(start 273.37258 -222.593154)
		(end 273.37258 -222.882714)
		(width 0.20066)
		(layer "F.Cu")
		(net "M_C_CPU0_SB_DQ<8>")
	)
	(segment
		(start 343.60358 -239.57534)
		(end 343.603834 -239.575086)
		(width 0.20066)
		(layer "F.Cu")
		(net "M_C_CPU0_SB_DQ<8>")
	)
	(segment
		(start 276.469094 -222.391732)
		(end 274.40001 -222.391732)
		(width 0.1016)
		(layer "F.Cu")
		(net "M_C_CPU0_SB_DQ<8>")
	)
	(segment
		(start 343.603834 -239.575086)
		(end 343.603834 -239.0394)
		(width 0.20066)
		(layer "F.Cu")
		(net "M_C_CPU0_SB_DQ<8>")
	)
	(segment
		(start 272.502376 -222.816674)
		(end 271.168114 -222.816674)
		(width 0.20066)
		(layer "F.Cu")
		(net "M_C_CPU0_SB_DQ<8>")
	)
	(segment
		(start 309.585868 -229.191566)
		(end 309.425848 -229.031546)
		(width 0.18288)
		(layer "In6.Cu")
		(net "M_C_CPU0_SB_DQ<8>")
	)
	(segment
		(start 309.425848 -229.031546)
		(end 309.425848 -228.698806)
		(width 0.18288)
		(layer "In6.Cu")
		(net "M_C_CPU0_SB_DQ<8>")
	)
	(segment
		(start 281.11577 -223.42475)
		(end 280.93289 -223.24187)
		(width 0.18288)
		(layer "In6.Cu")
		(net "M_C_CPU0_SB_DQ<8>")
	)
	(segment
		(start 290.917884 -224.99066)
		(end 290.735004 -224.80778)
		(width 0.18288)
		(layer "In6.Cu")
		(net "M_C_CPU0_SB_DQ<8>")
	)
	(segment
		(start 285.619952 -223.018858)
		(end 284.840426 -223.018858)
		(width 0.18288)
		(layer "In6.Cu")
		(net "M_C_CPU0_SB_DQ<8>")
	)
	(segment
		(start 304.542952 -227.59543)
		(end 304.319178 -227.371656)
		(width 0.18288)
		(layer "In6.Cu")
		(net "M_C_CPU0_SB_DQ<8>")
	)
	(segment
		(start 286.505904 -223.67875)
		(end 286.772604 -223.412304)
		(width 0.18288)
		(layer "In6.Cu")
		(net "M_C_CPU0_SB_DQ<8>")
	)
	(segment
		(start 305.233832 -227.371656)
		(end 305.010058 -227.59543)
		(width 0.18288)
		(layer "In6.Cu")
		(net "M_C_CPU0_SB_DQ<8>")
	)
	(segment
		(start 306.295552 -227.371656)
		(end 305.233832 -227.371656)
		(width 0.18288)
		(layer "In6.Cu")
		(net "M_C_CPU0_SB_DQ<8>")
	)
	(segment
		(start 290.735004 -224.495614)
		(end 290.552124 -224.312734)
		(width 0.18288)
		(layer "In6.Cu")
		(net "M_C_CPU0_SB_DQ<8>")
	)
	(segment
		(start 340.127082 -239.528858)
		(end 340.11235 -239.537494)
		(width 0.088646)
		(layer "In6.Cu")
		(net "M_C_CPU0_SB_DQ<8>")
	)
	(segment
		(start 314.573666 -230.895144)
		(end 313.591448 -230.895144)
		(width 0.18288)
		(layer "In6.Cu")
		(net "M_C_CPU0_SB_DQ<8>")
	)
	(segment
		(start 307.057552 -228.133656)
		(end 306.295552 -227.371656)
		(width 0.18288)
		(layer "In6.Cu")
		(net "M_C_CPU0_SB_DQ<8>")
	)
	(segment
		(start 338.247736 -239.528858)
		(end 338.237322 -239.534954)
		(width 0.088646)
		(layer "In6.Cu")
		(net "M_C_CPU0_SB_DQ<8>")
	)
	(segment
		(start 286.772604 -223.186244)
		(end 286.574738 -222.988378)
		(width 0.18288)
		(layer "In6.Cu")
		(net "M_C_CPU0_SB_DQ<8>")
	)
	(segment
		(start 284.617414 -223.24187)
		(end 281.98953 -223.24187)
		(width 0.18288)
		(layer "In6.Cu")
		(net "M_C_CPU0_SB_DQ<8>")
	)
	(segment
		(start 290.735004 -224.80778)
		(end 290.735004 -224.495614)
		(width 0.18288)
		(layer "In6.Cu")
		(net "M_C_CPU0_SB_DQ<8>")
	)
	(segment
		(start 332.700884 -239.0394)
		(end 332.701138 -239.0394)
		(width 0.088646)
		(layer "In6.Cu")
		(net "M_C_CPU0_SB_DQ<8>")
	)
	(segment
		(start 302.898048 -226.641406)
		(end 301.721266 -226.641406)
		(width 0.18288)
		(layer "In6.Cu")
		(net "M_C_CPU0_SB_DQ<8>")
	)
	(segment
		(start 284.840426 -223.018858)
		(end 284.617414 -223.24187)
		(width 0.18288)
		(layer "In6.Cu")
		(net "M_C_CPU0_SB_DQ<8>")
	)
	(segment
		(start 332.326234 -238.66475)
		(end 331.837538 -238.66475)
		(width 0.088646)
		(layer "In6.Cu")
		(net "M_C_CPU0_SB_DQ<8>")
	)
	(segment
		(start 301.538386 -226.824286)
		(end 301.538386 -227.108512)
		(width 0.18288)
		(layer "In6.Cu")
		(net "M_C_CPU0_SB_DQ<8>")
	)
	(segment
		(start 290.227004 -224.312734)
		(end 290.044124 -224.495614)
		(width 0.18288)
		(layer "In6.Cu")
		(net "M_C_CPU0_SB_DQ<8>")
	)
	(segment
		(start 281.98953 -223.24187)
		(end 281.80665 -223.42475)
		(width 0.18288)
		(layer "In6.Cu")
		(net "M_C_CPU0_SB_DQ<8>")
	)
	(segment
		(start 336.367882 -239.528858)
		(end 336.35315 -239.537494)
		(width 0.088646)
		(layer "In6.Cu")
		(net "M_C_CPU0_SB_DQ<8>")
	)
	(segment
		(start 321.185794 -237.507272)
		(end 314.573666 -230.895144)
		(width 0.18288)
		(layer "In6.Cu")
		(net "M_C_CPU0_SB_DQ<8>")
	)
	(segment
		(start 332.701138 -239.0394)
		(end 332.701138 -239.031526)
		(width 0.088646)
		(layer "In6.Cu")
		(net "M_C_CPU0_SB_DQ<8>")
	)
	(segment
		(start 331.086206 -237.913418)
		(end 331.086206 -237.595918)
		(width 0.088646)
		(layer "In6.Cu")
		(net "M_C_CPU0_SB_DQ<8>")
	)
	(segment
		(start 281.80665 -223.825816)
		(end 281.62377 -224.008696)
		(width 0.18288)
		(layer "In6.Cu")
		(net "M_C_CPU0_SB_DQ<8>")
	)
	(segment
		(start 330.775564 -237.507272)
		(end 321.185794 -237.507272)
		(width 0.18288)
		(layer "In6.Cu")
		(net "M_C_CPU0_SB_DQ<8>")
	)
	(segment
		(start 286.772604 -223.412304)
		(end 286.772604 -223.186244)
		(width 0.18288)
		(layer "In6.Cu")
		(net "M_C_CPU0_SB_DQ<8>")
	)
	(segment
		(start 290.044124 -224.495614)
		(end 290.044124 -224.80778)
		(width 0.18288)
		(layer "In6.Cu")
		(net "M_C_CPU0_SB_DQ<8>")
	)
	(segment
		(start 331.086206 -237.595918)
		(end 330.99756 -237.507272)
		(width 0.088646)
		(layer "In6.Cu")
		(net "M_C_CPU0_SB_DQ<8>")
	)
	(segment
		(start 301.721266 -226.641406)
		(end 301.538386 -226.824286)
		(width 0.18288)
		(layer "In6.Cu")
		(net "M_C_CPU0_SB_DQ<8>")
	)
	(segment
		(start 300.664626 -226.641406)
		(end 298.039282 -226.641406)
		(width 0.18288)
		(layer "In6.Cu")
		(net "M_C_CPU0_SB_DQ<8>")
	)
	(segment
		(start 303.628298 -227.371656)
		(end 302.898048 -226.641406)
		(width 0.18288)
		(layer "In6.Cu")
		(net "M_C_CPU0_SB_DQ<8>")
	)
	(segment
		(start 290.552124 -224.312734)
		(end 290.227004 -224.312734)
		(width 0.18288)
		(layer "In6.Cu")
		(net "M_C_CPU0_SB_DQ<8>")
	)
	(segment
		(start 297.189398 -225.791522)
		(end 292.223444 -225.791522)
		(width 0.18288)
		(layer "In6.Cu")
		(net "M_C_CPU0_SB_DQ<8>")
	)
	(segment
		(start 286.709866 -224.108772)
		(end 286.505904 -223.90481)
		(width 0.18288)
		(layer "In6.Cu")
		(net "M_C_CPU0_SB_DQ<8>")
	)
	(segment
		(start 335.428082 -239.528858)
		(end 335.41335 -239.537494)
		(width 0.088646)
		(layer "In6.Cu")
		(net "M_C_CPU0_SB_DQ<8>")
	)
	(segment
		(start 332.700884 -239.054894)
		(end 332.700884 -239.0394)
		(width 0.088646)
		(layer "In6.Cu")
		(net "M_C_CPU0_SB_DQ<8>")
	)
	(segment
		(start 309.425848 -228.698806)
		(end 308.860698 -228.133656)
		(width 0.18288)
		(layer "In6.Cu")
		(net "M_C_CPU0_SB_DQ<8>")
	)
	(segment
		(start 286.574738 -222.988378)
		(end 286.348678 -222.988378)
		(width 0.18288)
		(layer "In6.Cu")
		(net "M_C_CPU0_SB_DQ<8>")
	)
	(segment
		(start 281.80665 -223.42475)
		(end 281.80665 -223.825816)
		(width 0.18288)
		(layer "In6.Cu")
		(net "M_C_CPU0_SB_DQ<8>")
	)
	(segment
		(start 286.505904 -223.90481)
		(end 286.505904 -223.67875)
		(width 0.18288)
		(layer "In6.Cu")
		(net "M_C_CPU0_SB_DQ<8>")
	)
	(segment
		(start 285.855918 -223.254824)
		(end 285.619952 -223.018858)
		(width 0.18288)
		(layer "In6.Cu")
		(net "M_C_CPU0_SB_DQ<8>")
	)
	(segment
		(start 292.223444 -225.791522)
		(end 291.422582 -224.99066)
		(width 0.18288)
		(layer "In6.Cu")
		(net "M_C_CPU0_SB_DQ<8>")
	)
	(segment
		(start 301.538386 -227.108512)
		(end 301.355506 -227.291392)
		(width 0.18288)
		(layer "In6.Cu")
		(net "M_C_CPU0_SB_DQ<8>")
	)
	(segment
		(start 313.591448 -230.895144)
		(end 311.88787 -229.191566)
		(width 0.18288)
		(layer "In6.Cu")
		(net "M_C_CPU0_SB_DQ<8>")
	)
	(segment
		(start 304.319178 -227.371656)
		(end 303.628298 -227.371656)
		(width 0.18288)
		(layer "In6.Cu")
		(net "M_C_CPU0_SB_DQ<8>")
	)
	(segment
		(start 342.006682 -239.528858)
		(end 341.99195 -239.537494)
		(width 0.088646)
		(layer "In6.Cu")
		(net "M_C_CPU0_SB_DQ<8>")
	)
	(segment
		(start 342.958674 -239.521746)
		(end 342.946482 -239.528858)
		(width 0.088646)
		(layer "In6.Cu")
		(net "M_C_CPU0_SB_DQ<8>")
	)
	(segment
		(start 311.88787 -229.191566)
		(end 309.585868 -229.191566)
		(width 0.18288)
		(layer "In6.Cu")
		(net "M_C_CPU0_SB_DQ<8>")
	)
	(segment
		(start 301.030386 -227.291392)
		(end 300.847506 -227.108512)
		(width 0.18288)
		(layer "In6.Cu")
		(net "M_C_CPU0_SB_DQ<8>")
	)
	(segment
		(start 281.11577 -223.825816)
		(end 281.11577 -223.42475)
		(width 0.18288)
		(layer "In6.Cu")
		(net "M_C_CPU0_SB_DQ<8>")
	)
	(segment
		(start 290.044124 -224.80778)
		(end 289.861244 -224.99066)
		(width 0.18288)
		(layer "In6.Cu")
		(net "M_C_CPU0_SB_DQ<8>")
	)
	(segment
		(start 281.29865 -224.008696)
		(end 281.11577 -223.825816)
		(width 0.18288)
		(layer "In6.Cu")
		(net "M_C_CPU0_SB_DQ<8>")
	)
	(segment
		(start 339.187282 -239.528858)
		(end 339.176868 -239.534954)
		(width 0.088646)
		(layer "In6.Cu")
		(net "M_C_CPU0_SB_DQ<8>")
	)
	(segment
		(start 289.089084 -224.99066)
		(end 288.207196 -224.108772)
		(width 0.18288)
		(layer "In6.Cu")
		(net "M_C_CPU0_SB_DQ<8>")
	)
	(segment
		(start 280.24201 -223.24187)
		(end 279.816814 -222.816674)
		(width 0.18288)
		(layer "In6.Cu")
		(net "M_C_CPU0_SB_DQ<8>")
	)
	(segment
		(start 341.066882 -239.528858)
		(end 341.05215 -239.537494)
		(width 0.088646)
		(layer "In6.Cu")
		(net "M_C_CPU0_SB_DQ<8>")
	)
	(segment
		(start 330.99756 -237.507272)
		(end 330.775564 -237.507272)
		(width 0.088646)
		(layer "In6.Cu")
		(net "M_C_CPU0_SB_DQ<8>")
	)
	(segment
		(start 281.62377 -224.008696)
		(end 281.29865 -224.008696)
		(width 0.18288)
		(layer "In6.Cu")
		(net "M_C_CPU0_SB_DQ<8>")
	)
	(segment
		(start 280.93289 -223.24187)
		(end 280.24201 -223.24187)
		(width 0.18288)
		(layer "In6.Cu")
		(net "M_C_CPU0_SB_DQ<8>")
	)
	(segment
		(start 301.355506 -227.291392)
		(end 301.030386 -227.291392)
		(width 0.18288)
		(layer "In6.Cu")
		(net "M_C_CPU0_SB_DQ<8>")
	)
	(segment
		(start 331.837538 -238.66475)
		(end 331.086206 -237.913418)
		(width 0.088646)
		(layer "In6.Cu")
		(net "M_C_CPU0_SB_DQ<8>")
	)
	(segment
		(start 334.488282 -239.528858)
		(end 334.47355 -239.537494)
		(width 0.088646)
		(layer "In6.Cu")
		(net "M_C_CPU0_SB_DQ<8>")
	)
	(segment
		(start 288.207196 -224.108772)
		(end 286.709866 -224.108772)
		(width 0.18288)
		(layer "In6.Cu")
		(net "M_C_CPU0_SB_DQ<8>")
	)
	(segment
		(start 291.422582 -224.99066)
		(end 290.917884 -224.99066)
		(width 0.18288)
		(layer "In6.Cu")
		(net "M_C_CPU0_SB_DQ<8>")
	)
	(segment
		(start 300.847506 -226.824286)
		(end 300.664626 -226.641406)
		(width 0.18288)
		(layer "In6.Cu")
		(net "M_C_CPU0_SB_DQ<8>")
	)
	(segment
		(start 333.548482 -239.528858)
		(end 333.53375 -239.537494)
		(width 0.088646)
		(layer "In6.Cu")
		(net "M_C_CPU0_SB_DQ<8>")
	)
	(segment
		(start 289.861244 -224.99066)
		(end 289.089084 -224.99066)
		(width 0.18288)
		(layer "In6.Cu")
		(net "M_C_CPU0_SB_DQ<8>")
	)
	(segment
		(start 305.010058 -227.59543)
		(end 304.542952 -227.59543)
		(width 0.18288)
		(layer "In6.Cu")
		(net "M_C_CPU0_SB_DQ<8>")
	)
	(segment
		(start 286.348678 -222.988378)
		(end 286.081978 -223.254824)
		(width 0.18288)
		(layer "In6.Cu")
		(net "M_C_CPU0_SB_DQ<8>")
	)
	(segment
		(start 298.039282 -226.641406)
		(end 297.189398 -225.791522)
		(width 0.18288)
		(layer "In6.Cu")
		(net "M_C_CPU0_SB_DQ<8>")
	)
	(segment
		(start 337.307682 -239.528858)
		(end 337.29295 -239.537494)
		(width 0.088646)
		(layer "In6.Cu")
		(net "M_C_CPU0_SB_DQ<8>")
	)
	(segment
		(start 308.860698 -228.133656)
		(end 307.057552 -228.133656)
		(width 0.18288)
		(layer "In6.Cu")
		(net "M_C_CPU0_SB_DQ<8>")
	)
	(segment
		(start 300.847506 -227.108512)
		(end 300.847506 -226.824286)
		(width 0.18288)
		(layer "In6.Cu")
		(net "M_C_CPU0_SB_DQ<8>")
	)
	(segment
		(start 286.081978 -223.254824)
		(end 285.855918 -223.254824)
		(width 0.18288)
		(layer "In6.Cu")
		(net "M_C_CPU0_SB_DQ<8>")
	)
	(arc
		(start 340.11235 -239.537494)
		(mid 339.835875 -239.604814)
		(end 339.561678 -239.528858)
		(width 0.088646)
		(layer "In6.Cu")
		(net "M_C_CPU0_SB_DQ<8>")
	)
	(arc
		(start 342.946482 -239.528858)
		(mid 342.66378 -239.604634)
		(end 342.381078 -239.528858)
		(width 0.088646)
		(layer "In6.Cu")
		(net "M_C_CPU0_SB_DQ<8>")
	)
	(arc
		(start 343.603834 -239.0394)
		(mid 343.295003 -239.298963)
		(end 342.958674 -239.521746)
		(width 0.088646)
		(layer "In6.Cu")
		(net "M_C_CPU0_SB_DQ<8>")
	)
	(arc
		(start 338.622132 -239.528858)
		(mid 338.434934 -239.478715)
		(end 338.247736 -239.528858)
		(width 0.088646)
		(layer "In6.Cu")
		(net "M_C_CPU0_SB_DQ<8>")
	)
	(arc
		(start 338.237322 -239.534954)
		(mid 337.95889 -239.6048)
		(end 337.682078 -239.528858)
		(width 0.088646)
		(layer "In6.Cu")
		(net "M_C_CPU0_SB_DQ<8>")
	)
	(arc
		(start 332.983078 -239.528858)
		(mid 332.780255 -239.328627)
		(end 332.700884 -239.054894)
		(width 0.088646)
		(layer "In6.Cu")
		(net "M_C_CPU0_SB_DQ<8>")
	)
	(arc
		(start 332.701138 -239.031526)
		(mid 332.588504 -238.771636)
		(end 332.326234 -238.66475)
		(width 0.088646)
		(layer "In6.Cu")
		(net "M_C_CPU0_SB_DQ<8>")
	)
	(arc
		(start 339.176868 -239.534954)
		(mid 338.89869 -239.604677)
		(end 338.622132 -239.528858)
		(width 0.088646)
		(layer "In6.Cu")
		(net "M_C_CPU0_SB_DQ<8>")
	)
	(arc
		(start 339.561678 -239.528858)
		(mid 339.37448 -239.478715)
		(end 339.187282 -239.528858)
		(width 0.088646)
		(layer "In6.Cu")
		(net "M_C_CPU0_SB_DQ<8>")
	)
	(arc
		(start 337.29295 -239.537494)
		(mid 337.016475 -239.604814)
		(end 336.742278 -239.528858)
		(width 0.088646)
		(layer "In6.Cu")
		(net "M_C_CPU0_SB_DQ<8>")
	)
	(arc
		(start 334.47355 -239.537494)
		(mid 334.197075 -239.604814)
		(end 333.922878 -239.528858)
		(width 0.088646)
		(layer "In6.Cu")
		(net "M_C_CPU0_SB_DQ<8>")
	)
	(arc
		(start 342.381078 -239.528858)
		(mid 342.19388 -239.478715)
		(end 342.006682 -239.528858)
		(width 0.088646)
		(layer "In6.Cu")
		(net "M_C_CPU0_SB_DQ<8>")
	)
	(arc
		(start 334.862678 -239.528858)
		(mid 334.67548 -239.478715)
		(end 334.488282 -239.528858)
		(width 0.088646)
		(layer "In6.Cu")
		(net "M_C_CPU0_SB_DQ<8>")
	)
	(arc
		(start 340.501478 -239.528858)
		(mid 340.31428 -239.478715)
		(end 340.127082 -239.528858)
		(width 0.088646)
		(layer "In6.Cu")
		(net "M_C_CPU0_SB_DQ<8>")
	)
	(arc
		(start 333.53375 -239.537494)
		(mid 333.257275 -239.604814)
		(end 332.983078 -239.528858)
		(width 0.088646)
		(layer "In6.Cu")
		(net "M_C_CPU0_SB_DQ<8>")
	)
	(arc
		(start 337.682078 -239.528858)
		(mid 337.49488 -239.478715)
		(end 337.307682 -239.528858)
		(width 0.088646)
		(layer "In6.Cu")
		(net "M_C_CPU0_SB_DQ<8>")
	)
	(arc
		(start 333.922878 -239.528858)
		(mid 333.73568 -239.478715)
		(end 333.548482 -239.528858)
		(width 0.088646)
		(layer "In6.Cu")
		(net "M_C_CPU0_SB_DQ<8>")
	)
	(arc
		(start 335.802478 -239.528858)
		(mid 335.61528 -239.478715)
		(end 335.428082 -239.528858)
		(width 0.088646)
		(layer "In6.Cu")
		(net "M_C_CPU0_SB_DQ<8>")
	)
	(arc
		(start 341.99195 -239.537494)
		(mid 341.715475 -239.604814)
		(end 341.441278 -239.528858)
		(width 0.088646)
		(layer "In6.Cu")
		(net "M_C_CPU0_SB_DQ<8>")
	)
	(arc
		(start 336.35315 -239.537494)
		(mid 336.076675 -239.604814)
		(end 335.802478 -239.528858)
		(width 0.088646)
		(layer "In6.Cu")
		(net "M_C_CPU0_SB_DQ<8>")
	)
	(arc
		(start 341.05215 -239.537494)
		(mid 340.775675 -239.604814)
		(end 340.501478 -239.528858)
		(width 0.088646)
		(layer "In6.Cu")
		(net "M_C_CPU0_SB_DQ<8>")
	)
	(arc
		(start 336.742278 -239.528858)
		(mid 336.55508 -239.478715)
		(end 336.367882 -239.528858)
		(width 0.088646)
		(layer "In6.Cu")
		(net "M_C_CPU0_SB_DQ<8>")
	)
	(arc
		(start 341.441278 -239.528858)
		(mid 341.25408 -239.478715)
		(end 341.066882 -239.528858)
		(width 0.088646)
		(layer "In6.Cu")
		(net "M_C_CPU0_SB_DQ<8>")
	)
	(arc
		(start 335.41335 -239.537494)
		(mid 335.136875 -239.604814)
		(end 334.862678 -239.528858)
		(width 0.088646)
		(layer "In6.Cu")
		(net "M_C_CPU0_SB_DQ<8>")
	)
	(segment
		(start 280.73477 -223.66224)
		(end 280.606246 -223.790764)
		(width 0.20066)
		(layer "F.Cu")
		(net "M_C_CPU0_SB_DQ<7>")
	)
	(segment
		(start 281.99588 -223.666558)
		(end 281.788362 -223.874076)
		(width 0.20066)
		(layer "F.Cu")
		(net "M_C_CPU0_SB_DQ<7>")
	)
	(segment
		(start 280.457148 -224.0915)
		(end 279.912826 -224.0915)
		(width 0.20066)
		(layer "F.Cu")
		(net "M_C_CPU0_SB_DQ<7>")
	)
	(segment
		(start 277.601934 -224.0915)
		(end 277.58771 -224.105724)
		(width 0.101854)
		(layer "F.Cu")
		(net "M_C_CPU0_SB_DQ<7>")
	)
	(segment
		(start 283.916882 -223.666558)
		(end 282.811982 -223.666558)
		(width 0.20066)
		(layer "F.Cu")
		(net "M_C_CPU0_SB_DQ<7>")
	)
	(segment
		(start 277.091394 -223.96323)
		(end 277.091394 -223.792542)
		(width 0.20066)
		(layer "F.Cu")
		(net "M_C_CPU0_SB_DQ<7>")
	)
	(segment
		(start 282.811982 -223.666558)
		(end 281.99588 -223.666558)
		(width 0.20066)
		(layer "F.Cu")
		(net "M_C_CPU0_SB_DQ<7>")
	)
	(segment
		(start 281.129994 -223.66224)
		(end 280.73477 -223.66224)
		(width 0.20066)
		(layer "F.Cu")
		(net "M_C_CPU0_SB_DQ<7>")
	)
	(segment
		(start 277.839932 -224.0915)
		(end 277.601934 -224.0915)
		(width 0.101854)
		(layer "F.Cu")
		(net "M_C_CPU0_SB_DQ<7>")
	)
	(segment
		(start 344.54338 -241.203226)
		(end 344.543634 -241.202972)
		(width 0.20066)
		(layer "F.Cu")
		(net "M_C_CPU0_SB_DQ<7>")
	)
	(segment
		(start 280.606246 -223.790764)
		(end 280.606246 -223.942402)
		(width 0.20066)
		(layer "F.Cu")
		(net "M_C_CPU0_SB_DQ<7>")
	)
	(segment
		(start 279.912826 -224.0915)
		(end 277.839932 -224.0915)
		(width 0.1016)
		(layer "F.Cu")
		(net "M_C_CPU0_SB_DQ<7>")
	)
	(segment
		(start 277.58771 -224.105724)
		(end 277.233888 -224.105724)
		(width 0.20066)
		(layer "F.Cu")
		(net "M_C_CPU0_SB_DQ<7>")
	)
	(segment
		(start 281.788362 -223.874076)
		(end 281.34183 -223.874076)
		(width 0.20066)
		(layer "F.Cu")
		(net "M_C_CPU0_SB_DQ<7>")
	)
	(segment
		(start 280.606246 -223.942402)
		(end 280.457148 -224.0915)
		(width 0.20066)
		(layer "F.Cu")
		(net "M_C_CPU0_SB_DQ<7>")
	)
	(segment
		(start 344.543634 -241.202972)
		(end 344.543634 -240.667286)
		(width 0.20066)
		(layer "F.Cu")
		(net "M_C_CPU0_SB_DQ<7>")
	)
	(segment
		(start 277.091394 -223.792542)
		(end 276.96541 -223.666558)
		(width 0.20066)
		(layer "F.Cu")
		(net "M_C_CPU0_SB_DQ<7>")
	)
	(segment
		(start 281.34183 -223.874076)
		(end 281.129994 -223.66224)
		(width 0.20066)
		(layer "F.Cu")
		(net "M_C_CPU0_SB_DQ<7>")
	)
	(segment
		(start 277.233888 -224.105724)
		(end 277.091394 -223.96323)
		(width 0.20066)
		(layer "F.Cu")
		(net "M_C_CPU0_SB_DQ<7>")
	)
	(segment
		(start 276.96541 -223.666558)
		(end 275.268182 -223.666558)
		(width 0.20066)
		(layer "F.Cu")
		(net "M_C_CPU0_SB_DQ<7>")
	)
	(segment
		(start 286.371284 -224.907856)
		(end 285.718504 -224.255076)
		(width 0.18288)
		(layer "In6.Cu")
		(net "M_C_CPU0_SB_DQ<7>")
	)
	(segment
		(start 332.992222 -240.171478)
		(end 332.981808 -240.177574)
		(width 0.088646)
		(layer "In6.Cu")
		(net "M_C_CPU0_SB_DQ<7>")
	)
	(segment
		(start 334.880458 -240.16716)
		(end 334.862424 -240.177574)
		(width 0.088646)
		(layer "In6.Cu")
		(net "M_C_CPU0_SB_DQ<7>")
	)
	(segment
		(start 301.829978 -228.49586)
		(end 301.669958 -228.65588)
		(width 0.18288)
		(layer "In6.Cu")
		(net "M_C_CPU0_SB_DQ<7>")
	)
	(segment
		(start 332.25359 -239.842802)
		(end 332.017116 -239.272064)
		(width 0.088646)
		(layer "In6.Cu")
		(net "M_C_CPU0_SB_DQ<7>")
	)
	(segment
		(start 300.443138 -228.243892)
		(end 300.443138 -228.49586)
		(width 0.18288)
		(layer "In6.Cu")
		(net "M_C_CPU0_SB_DQ<7>")
	)
	(segment
		(start 305.497992 -228.420168)
		(end 305.172872 -228.420168)
		(width 0.18288)
		(layer "In6.Cu")
		(net "M_C_CPU0_SB_DQ<7>")
	)
	(segment
		(start 304.989992 -228.603048)
		(end 304.989992 -229.009956)
		(width 0.18288)
		(layer "In6.Cu")
		(net "M_C_CPU0_SB_DQ<7>")
	)
	(segment
		(start 285.718504 -224.255076)
		(end 284.5054 -224.255076)
		(width 0.18288)
		(layer "In6.Cu")
		(net "M_C_CPU0_SB_DQ<7>")
	)
	(segment
		(start 303.91354 -229.192836)
		(end 303.376584 -228.65588)
		(width 0.18288)
		(layer "In6.Cu")
		(net "M_C_CPU0_SB_DQ<7>")
	)
	(segment
		(start 338.247736 -240.177574)
		(end 338.237322 -240.171478)
		(width 0.088646)
		(layer "In6.Cu")
		(net "M_C_CPU0_SB_DQ<7>")
	)
	(segment
		(start 302.523398 -228.49586)
		(end 302.523398 -227.974652)
		(width 0.18288)
		(layer "In6.Cu")
		(net "M_C_CPU0_SB_DQ<7>")
	)
	(segment
		(start 344.23096 -240.667286)
		(end 344.165428 -240.601754)
		(width 0.088646)
		(layer "In6.Cu")
		(net "M_C_CPU0_SB_DQ<7>")
	)
	(segment
		(start 300.976538 -228.083872)
		(end 300.603158 -228.083872)
		(width 0.18288)
		(layer "In6.Cu")
		(net "M_C_CPU0_SB_DQ<7>")
	)
	(segment
		(start 342.946482 -240.177574)
		(end 342.93175 -240.168938)
		(width 0.088646)
		(layer "In6.Cu")
		(net "M_C_CPU0_SB_DQ<7>")
	)
	(segment
		(start 340.127082 -240.177574)
		(end 340.11235 -240.168938)
		(width 0.088646)
		(layer "In6.Cu")
		(net "M_C_CPU0_SB_DQ<7>")
	)
	(segment
		(start 300.603158 -228.083872)
		(end 300.443138 -228.243892)
		(width 0.18288)
		(layer "In6.Cu")
		(net "M_C_CPU0_SB_DQ<7>")
	)
	(segment
		(start 287.823402 -224.907856)
		(end 286.371284 -224.907856)
		(width 0.18288)
		(layer "In6.Cu")
		(net "M_C_CPU0_SB_DQ<7>")
	)
	(segment
		(start 298.138342 -228.341174)
		(end 296.43832 -226.641152)
		(width 0.18288)
		(layer "In6.Cu")
		(net "M_C_CPU0_SB_DQ<7>")
	)
	(segment
		(start 311.677558 -231.054656)
		(end 310.664352 -230.04145)
		(width 0.18288)
		(layer "In6.Cu")
		(net "M_C_CPU0_SB_DQ<7>")
	)
	(segment
		(start 301.669958 -228.65588)
		(end 301.296578 -228.65588)
		(width 0.18288)
		(layer "In6.Cu")
		(net "M_C_CPU0_SB_DQ<7>")
	)
	(segment
		(start 335.435956 -240.1824)
		(end 335.427574 -240.177574)
		(width 0.088646)
		(layer "In6.Cu")
		(net "M_C_CPU0_SB_DQ<7>")
	)
	(segment
		(start 342.006682 -240.177574)
		(end 341.99195 -240.168938)
		(width 0.088646)
		(layer "In6.Cu")
		(net "M_C_CPU0_SB_DQ<7>")
	)
	(segment
		(start 334.862424 -240.177574)
		(end 334.847946 -240.185956)
		(width 0.088646)
		(layer "In6.Cu")
		(net "M_C_CPU0_SB_DQ<7>")
	)
	(segment
		(start 305.680872 -228.603048)
		(end 305.497992 -228.420168)
		(width 0.18288)
		(layer "In6.Cu")
		(net "M_C_CPU0_SB_DQ<7>")
	)
	(segment
		(start 299.961554 -228.65588)
		(end 299.646848 -228.341174)
		(width 0.18288)
		(layer "In6.Cu")
		(net "M_C_CPU0_SB_DQ<7>")
	)
	(segment
		(start 284.5054 -224.255076)
		(end 283.916882 -223.666558)
		(width 0.18288)
		(layer "In6.Cu")
		(net "M_C_CPU0_SB_DQ<7>")
	)
	(segment
		(start 336.367882 -240.177574)
		(end 336.349848 -240.16716)
		(width 0.088646)
		(layer "In6.Cu")
		(net "M_C_CPU0_SB_DQ<7>")
	)
	(segment
		(start 332.52918 -240.118646)
		(end 332.52918 -240.118392)
		(width 0.088646)
		(layer "In6.Cu")
		(net "M_C_CPU0_SB_DQ<7>")
	)
	(segment
		(start 291.195252 -226.641152)
		(end 290.343082 -225.788982)
		(width 0.18288)
		(layer "In6.Cu")
		(net "M_C_CPU0_SB_DQ<7>")
	)
	(segment
		(start 308.953662 -230.04145)
		(end 308.105048 -229.192836)
		(width 0.18288)
		(layer "In6.Cu")
		(net "M_C_CPU0_SB_DQ<7>")
	)
	(segment
		(start 305.863752 -229.192836)
		(end 305.680872 -229.009956)
		(width 0.18288)
		(layer "In6.Cu")
		(net "M_C_CPU0_SB_DQ<7>")
	)
	(segment
		(start 290.343082 -225.788982)
		(end 288.704528 -225.788982)
		(width 0.18288)
		(layer "In6.Cu")
		(net "M_C_CPU0_SB_DQ<7>")
	)
	(segment
		(start 288.704528 -225.788982)
		(end 287.823402 -224.907856)
		(width 0.18288)
		(layer "In6.Cu")
		(net "M_C_CPU0_SB_DQ<7>")
	)
	(segment
		(start 299.646848 -228.341174)
		(end 298.138342 -228.341174)
		(width 0.18288)
		(layer "In6.Cu")
		(net "M_C_CPU0_SB_DQ<7>")
	)
	(segment
		(start 301.136558 -228.49586)
		(end 301.136558 -228.243892)
		(width 0.18288)
		(layer "In6.Cu")
		(net "M_C_CPU0_SB_DQ<7>")
	)
	(segment
		(start 300.443138 -228.49586)
		(end 300.283118 -228.65588)
		(width 0.18288)
		(layer "In6.Cu")
		(net "M_C_CPU0_SB_DQ<7>")
	)
	(segment
		(start 330.775564 -238.299752)
		(end 320.61277 -238.299752)
		(width 0.18288)
		(layer "In6.Cu")
		(net "M_C_CPU0_SB_DQ<7>")
	)
	(segment
		(start 301.296578 -228.65588)
		(end 301.136558 -228.49586)
		(width 0.18288)
		(layer "In6.Cu")
		(net "M_C_CPU0_SB_DQ<7>")
	)
	(segment
		(start 320.61277 -238.299752)
		(end 314.988448 -232.67543)
		(width 0.18288)
		(layer "In6.Cu")
		(net "M_C_CPU0_SB_DQ<7>")
	)
	(segment
		(start 332.52918 -240.118392)
		(end 332.25359 -239.842802)
		(width 0.088646)
		(layer "In6.Cu")
		(net "M_C_CPU0_SB_DQ<7>")
	)
	(segment
		(start 301.136558 -228.243892)
		(end 300.976538 -228.083872)
		(width 0.18288)
		(layer "In6.Cu")
		(net "M_C_CPU0_SB_DQ<7>")
	)
	(segment
		(start 304.807112 -229.192836)
		(end 303.91354 -229.192836)
		(width 0.18288)
		(layer "In6.Cu")
		(net "M_C_CPU0_SB_DQ<7>")
	)
	(segment
		(start 337.307682 -240.177574)
		(end 337.29295 -240.168938)
		(width 0.088646)
		(layer "In6.Cu")
		(net "M_C_CPU0_SB_DQ<7>")
	)
	(segment
		(start 310.664352 -230.04145)
		(end 308.953662 -230.04145)
		(width 0.18288)
		(layer "In6.Cu")
		(net "M_C_CPU0_SB_DQ<7>")
	)
	(segment
		(start 305.680872 -229.009956)
		(end 305.680872 -228.603048)
		(width 0.18288)
		(layer "In6.Cu")
		(net "M_C_CPU0_SB_DQ<7>")
	)
	(segment
		(start 314.988448 -232.67543)
		(end 313.798458 -232.67543)
		(width 0.18288)
		(layer "In6.Cu")
		(net "M_C_CPU0_SB_DQ<7>")
	)
	(segment
		(start 305.172872 -228.420168)
		(end 304.989992 -228.603048)
		(width 0.18288)
		(layer "In6.Cu")
		(net "M_C_CPU0_SB_DQ<7>")
	)
	(segment
		(start 300.283118 -228.65588)
		(end 299.961554 -228.65588)
		(width 0.18288)
		(layer "In6.Cu")
		(net "M_C_CPU0_SB_DQ<7>")
	)
	(segment
		(start 302.363378 -227.814632)
		(end 302.024796 -227.814632)
		(width 0.18288)
		(layer "In6.Cu")
		(net "M_C_CPU0_SB_DQ<7>")
	)
	(segment
		(start 301.829978 -228.00945)
		(end 301.829978 -228.49586)
		(width 0.18288)
		(layer "In6.Cu")
		(net "M_C_CPU0_SB_DQ<7>")
	)
	(segment
		(start 344.543634 -240.667286)
		(end 344.23096 -240.667286)
		(width 0.088646)
		(layer "In6.Cu")
		(net "M_C_CPU0_SB_DQ<7>")
	)
	(segment
		(start 303.376584 -228.65588)
		(end 302.683418 -228.65588)
		(width 0.18288)
		(layer "In6.Cu")
		(net "M_C_CPU0_SB_DQ<7>")
	)
	(segment
		(start 313.798458 -232.67543)
		(end 312.177684 -231.054656)
		(width 0.18288)
		(layer "In6.Cu")
		(net "M_C_CPU0_SB_DQ<7>")
	)
	(segment
		(start 331.044804 -238.299752)
		(end 330.775564 -238.299752)
		(width 0.088646)
		(layer "In6.Cu")
		(net "M_C_CPU0_SB_DQ<7>")
	)
	(segment
		(start 333.936594 -240.168938)
		(end 333.921862 -240.177574)
		(width 0.088646)
		(layer "In6.Cu")
		(net "M_C_CPU0_SB_DQ<7>")
	)
	(segment
		(start 341.066882 -240.177574)
		(end 341.05215 -240.168938)
		(width 0.088646)
		(layer "In6.Cu")
		(net "M_C_CPU0_SB_DQ<7>")
	)
	(segment
		(start 312.177684 -231.054656)
		(end 311.677558 -231.054656)
		(width 0.18288)
		(layer "In6.Cu")
		(net "M_C_CPU0_SB_DQ<7>")
	)
	(segment
		(start 338.632546 -240.171478)
		(end 338.622132 -240.177574)
		(width 0.088646)
		(layer "In6.Cu")
		(net "M_C_CPU0_SB_DQ<7>")
	)
	(segment
		(start 308.105048 -229.192836)
		(end 305.863752 -229.192836)
		(width 0.18288)
		(layer "In6.Cu")
		(net "M_C_CPU0_SB_DQ<7>")
	)
	(segment
		(start 302.523398 -227.974652)
		(end 302.363378 -227.814632)
		(width 0.18288)
		(layer "In6.Cu")
		(net "M_C_CPU0_SB_DQ<7>")
	)
	(segment
		(start 332.017116 -239.272064)
		(end 331.044804 -238.299752)
		(width 0.088646)
		(layer "In6.Cu")
		(net "M_C_CPU0_SB_DQ<7>")
	)
	(segment
		(start 304.989992 -229.009956)
		(end 304.807112 -229.192836)
		(width 0.18288)
		(layer "In6.Cu")
		(net "M_C_CPU0_SB_DQ<7>")
	)
	(segment
		(start 302.683418 -228.65588)
		(end 302.523398 -228.49586)
		(width 0.18288)
		(layer "In6.Cu")
		(net "M_C_CPU0_SB_DQ<7>")
	)
	(segment
		(start 302.024796 -227.814632)
		(end 301.829978 -228.00945)
		(width 0.18288)
		(layer "In6.Cu")
		(net "M_C_CPU0_SB_DQ<7>")
	)
	(segment
		(start 343.886282 -240.177574)
		(end 343.87155 -240.168938)
		(width 0.088646)
		(layer "In6.Cu")
		(net "M_C_CPU0_SB_DQ<7>")
	)
	(segment
		(start 296.43832 -226.641152)
		(end 291.195252 -226.641152)
		(width 0.18288)
		(layer "In6.Cu")
		(net "M_C_CPU0_SB_DQ<7>")
	)
	(arc
		(start 343.320878 -240.177574)
		(mid 343.13368 -240.227717)
		(end 342.946482 -240.177574)
		(width 0.088646)
		(layer "In6.Cu")
		(net "M_C_CPU0_SB_DQ<7>")
	)
	(arc
		(start 335.802224 -240.177574)
		(mid 335.619719 -240.227812)
		(end 335.435956 -240.1824)
		(width 0.088646)
		(layer "In6.Cu")
		(net "M_C_CPU0_SB_DQ<7>")
	)
	(arc
		(start 333.921862 -240.177574)
		(mid 333.734664 -240.227717)
		(end 333.547466 -240.177574)
		(width 0.088646)
		(layer "In6.Cu")
		(net "M_C_CPU0_SB_DQ<7>")
	)
	(arc
		(start 342.381078 -240.177574)
		(mid 342.19388 -240.227717)
		(end 342.006682 -240.177574)
		(width 0.088646)
		(layer "In6.Cu")
		(net "M_C_CPU0_SB_DQ<7>")
	)
	(arc
		(start 334.847946 -240.185956)
		(mid 334.666783 -240.227896)
		(end 334.487774 -240.177574)
		(width 0.088646)
		(layer "In6.Cu")
		(net "M_C_CPU0_SB_DQ<7>")
	)
	(arc
		(start 339.561678 -240.177574)
		(mid 339.37448 -240.227717)
		(end 339.187282 -240.177574)
		(width 0.088646)
		(layer "In6.Cu")
		(net "M_C_CPU0_SB_DQ<7>")
	)
	(arc
		(start 333.547466 -240.177574)
		(mid 333.270653 -240.101738)
		(end 332.992222 -240.171478)
		(width 0.088646)
		(layer "In6.Cu")
		(net "M_C_CPU0_SB_DQ<7>")
	)
	(arc
		(start 337.29295 -240.168938)
		(mid 337.016509 -240.101772)
		(end 336.742278 -240.177574)
		(width 0.088646)
		(layer "In6.Cu")
		(net "M_C_CPU0_SB_DQ<7>")
	)
	(arc
		(start 334.487774 -240.177574)
		(mid 334.213321 -240.101646)
		(end 333.936594 -240.168938)
		(width 0.088646)
		(layer "In6.Cu")
		(net "M_C_CPU0_SB_DQ<7>")
	)
	(arc
		(start 341.05215 -240.168938)
		(mid 340.775709 -240.101772)
		(end 340.501478 -240.177574)
		(width 0.088646)
		(layer "In6.Cu")
		(net "M_C_CPU0_SB_DQ<7>")
	)
	(arc
		(start 336.349848 -240.16716)
		(mid 336.07469 -240.101667)
		(end 335.802224 -240.177574)
		(width 0.088646)
		(layer "In6.Cu")
		(net "M_C_CPU0_SB_DQ<7>")
	)
	(arc
		(start 332.607412 -240.177574)
		(mid 332.566354 -240.150687)
		(end 332.52918 -240.118646)
		(width 0.088646)
		(layer "In6.Cu")
		(net "M_C_CPU0_SB_DQ<7>")
	)
	(arc
		(start 341.441278 -240.177574)
		(mid 341.25408 -240.227717)
		(end 341.066882 -240.177574)
		(width 0.088646)
		(layer "In6.Cu")
		(net "M_C_CPU0_SB_DQ<7>")
	)
	(arc
		(start 335.427574 -240.177574)
		(mid 335.155362 -240.101807)
		(end 334.880458 -240.16716)
		(width 0.088646)
		(layer "In6.Cu")
		(net "M_C_CPU0_SB_DQ<7>")
	)
	(arc
		(start 340.501478 -240.177574)
		(mid 340.31428 -240.227717)
		(end 340.127082 -240.177574)
		(width 0.088646)
		(layer "In6.Cu")
		(net "M_C_CPU0_SB_DQ<7>")
	)
	(arc
		(start 337.682078 -240.177574)
		(mid 337.49488 -240.227717)
		(end 337.307682 -240.177574)
		(width 0.088646)
		(layer "In6.Cu")
		(net "M_C_CPU0_SB_DQ<7>")
	)
	(arc
		(start 338.237322 -240.171478)
		(mid 337.95889 -240.101664)
		(end 337.682078 -240.177574)
		(width 0.088646)
		(layer "In6.Cu")
		(net "M_C_CPU0_SB_DQ<7>")
	)
	(arc
		(start 332.981808 -240.177574)
		(mid 332.79461 -240.227717)
		(end 332.607412 -240.177574)
		(width 0.088646)
		(layer "In6.Cu")
		(net "M_C_CPU0_SB_DQ<7>")
	)
	(arc
		(start 336.742278 -240.177574)
		(mid 336.55508 -240.227717)
		(end 336.367882 -240.177574)
		(width 0.088646)
		(layer "In6.Cu")
		(net "M_C_CPU0_SB_DQ<7>")
	)
	(arc
		(start 343.87155 -240.168938)
		(mid 343.595109 -240.101772)
		(end 343.320878 -240.177574)
		(width 0.088646)
		(layer "In6.Cu")
		(net "M_C_CPU0_SB_DQ<7>")
	)
	(arc
		(start 338.622132 -240.177574)
		(mid 338.434934 -240.227717)
		(end 338.247736 -240.177574)
		(width 0.088646)
		(layer "In6.Cu")
		(net "M_C_CPU0_SB_DQ<7>")
	)
	(arc
		(start 344.165428 -240.601754)
		(mid 344.076184 -240.356532)
		(end 343.886282 -240.177574)
		(width 0.088646)
		(layer "In6.Cu")
		(net "M_C_CPU0_SB_DQ<7>")
	)
	(arc
		(start 339.187282 -240.177574)
		(mid 338.910723 -240.101865)
		(end 338.632546 -240.171478)
		(width 0.088646)
		(layer "In6.Cu")
		(net "M_C_CPU0_SB_DQ<7>")
	)
	(arc
		(start 342.93175 -240.168938)
		(mid 342.655309 -240.101772)
		(end 342.381078 -240.177574)
		(width 0.088646)
		(layer "In6.Cu")
		(net "M_C_CPU0_SB_DQ<7>")
	)
	(arc
		(start 340.11235 -240.168938)
		(mid 339.835909 -240.101772)
		(end 339.561678 -240.177574)
		(width 0.088646)
		(layer "In6.Cu")
		(net "M_C_CPU0_SB_DQ<7>")
	)
	(arc
		(start 341.99195 -240.168938)
		(mid 341.715509 -240.101772)
		(end 341.441278 -240.177574)
		(width 0.088646)
		(layer "In6.Cu")
		(net "M_C_CPU0_SB_DQ<7>")
	)
	(segment
		(start 280.856944 -225.578416)
		(end 280.689558 -225.41103)
		(width 0.20066)
		(layer "F.Cu")
		(net "M_C_CPU0_SB_DQ<6>")
	)
	(segment
		(start 282.811982 -225.36658)
		(end 281.497278 -225.36658)
		(width 0.20066)
		(layer "F.Cu")
		(net "M_C_CPU0_SB_DQ<6>")
	)
	(segment
		(start 345.013534 -242.017042)
		(end 345.01328 -242.016788)
		(width 0.20066)
		(layer "F.Cu")
		(net "M_C_CPU0_SB_DQ<6>")
	)
	(segment
		(start 276.850348 -224.931478)
		(end 276.415246 -225.36658)
		(width 0.20066)
		(layer "F.Cu")
		(net "M_C_CPU0_SB_DQ<6>")
	)
	(segment
		(start 276.415246 -225.36658)
		(end 275.268182 -225.36658)
		(width 0.20066)
		(layer "F.Cu")
		(net "M_C_CPU0_SB_DQ<6>")
	)
	(segment
		(start 280.545794 -224.941638)
		(end 279.912826 -224.941638)
		(width 0.20066)
		(layer "F.Cu")
		(net "M_C_CPU0_SB_DQ<6>")
	)
	(segment
		(start 277.852886 -224.941638)
		(end 277.59787 -224.941638)
		(width 0.101854)
		(layer "F.Cu")
		(net "M_C_CPU0_SB_DQ<6>")
	)
	(segment
		(start 280.689558 -225.41103)
		(end 280.689558 -225.085402)
		(width 0.20066)
		(layer "F.Cu")
		(net "M_C_CPU0_SB_DQ<6>")
	)
	(segment
		(start 345.01328 -242.016788)
		(end 345.01328 -241.481102)
		(width 0.20066)
		(layer "F.Cu")
		(net "M_C_CPU0_SB_DQ<6>")
	)
	(segment
		(start 281.497278 -225.36658)
		(end 281.285442 -225.578416)
		(width 0.20066)
		(layer "F.Cu")
		(net "M_C_CPU0_SB_DQ<6>")
	)
	(segment
		(start 283.916882 -225.36658)
		(end 282.811982 -225.36658)
		(width 0.20066)
		(layer "F.Cu")
		(net "M_C_CPU0_SB_DQ<6>")
	)
	(segment
		(start 280.689558 -225.085402)
		(end 280.545794 -224.941638)
		(width 0.20066)
		(layer "F.Cu")
		(net "M_C_CPU0_SB_DQ<6>")
	)
	(segment
		(start 279.912826 -224.941638)
		(end 277.852886 -224.941638)
		(width 0.1016)
		(layer "F.Cu")
		(net "M_C_CPU0_SB_DQ<6>")
	)
	(segment
		(start 277.59787 -224.941638)
		(end 277.58771 -224.931478)
		(width 0.101854)
		(layer "F.Cu")
		(net "M_C_CPU0_SB_DQ<6>")
	)
	(segment
		(start 277.58771 -224.931478)
		(end 276.850348 -224.931478)
		(width 0.20066)
		(layer "F.Cu")
		(net "M_C_CPU0_SB_DQ<6>")
	)
	(segment
		(start 281.285442 -225.578416)
		(end 280.856944 -225.578416)
		(width 0.20066)
		(layer "F.Cu")
		(net "M_C_CPU0_SB_DQ<6>")
	)
	(segment
		(start 284.529276 -225.978974)
		(end 283.916882 -225.36658)
		(width 0.18288)
		(layer "In6.Cu")
		(net "M_C_CPU0_SB_DQ<6>")
	)
	(segment
		(start 299.540422 -230.041196)
		(end 297.771312 -230.041196)
		(width 0.18288)
		(layer "In6.Cu")
		(net "M_C_CPU0_SB_DQ<6>")
	)
	(segment
		(start 333.467964 -240.983008)
		(end 333.453232 -240.991644)
		(width 0.088646)
		(layer "In6.Cu")
		(net "M_C_CPU0_SB_DQ<6>")
	)
	(segment
		(start 305.25085 -230.423466)
		(end 305.06797 -230.606346)
		(width 0.18288)
		(layer "In6.Cu")
		(net "M_C_CPU0_SB_DQ<6>")
	)
	(segment
		(start 301.563786 -229.689152)
		(end 301.238666 -229.689152)
		(width 0.18288)
		(layer "In6.Cu")
		(net "M_C_CPU0_SB_DQ<6>")
	)
	(segment
		(start 296.917872 -229.881176)
		(end 296.757852 -230.041196)
		(width 0.18288)
		(layer "In6.Cu")
		(net "M_C_CPU0_SB_DQ<6>")
	)
	(segment
		(start 295.567354 -229.191566)
		(end 294.465248 -229.191566)
		(width 0.18288)
		(layer "In6.Cu")
		(net "M_C_CPU0_SB_DQ<6>")
	)
	(segment
		(start 297.451272 -229.422452)
		(end 297.077892 -229.422452)
		(width 0.18288)
		(layer "In6.Cu")
		(net "M_C_CPU0_SB_DQ<6>")
	)
	(segment
		(start 305.75885 -230.936546)
		(end 305.75885 -230.606346)
		(width 0.18288)
		(layer "In6.Cu")
		(net "M_C_CPU0_SB_DQ<6>")
	)
	(segment
		(start 343.805764 -240.983008)
		(end 343.791032 -240.991644)
		(width 0.088646)
		(layer "In6.Cu")
		(net "M_C_CPU0_SB_DQ<6>")
	)
	(segment
		(start 290.359592 -227.74275)
		(end 288.79673 -227.74275)
		(width 0.18288)
		(layer "In6.Cu")
		(net "M_C_CPU0_SB_DQ<6>")
	)
	(segment
		(start 340.046564 -240.983008)
		(end 340.031832 -240.991644)
		(width 0.088646)
		(layer "In6.Cu")
		(net "M_C_CPU0_SB_DQ<6>")
	)
	(segment
		(start 296.917872 -229.582472)
		(end 296.917872 -229.881176)
		(width 0.18288)
		(layer "In6.Cu")
		(net "M_C_CPU0_SB_DQ<6>")
	)
	(segment
		(start 293.294562 -228.02088)
		(end 292.802564 -228.02088)
		(width 0.18288)
		(layer "In6.Cu")
		(net "M_C_CPU0_SB_DQ<6>")
	)
	(segment
		(start 292.1635 -228.617018)
		(end 291.853366 -228.306884)
		(width 0.18288)
		(layer "In6.Cu")
		(net "M_C_CPU0_SB_DQ<6>")
	)
	(segment
		(start 292.802564 -228.02088)
		(end 292.642544 -228.1809)
		(width 0.18288)
		(layer "In6.Cu")
		(net "M_C_CPU0_SB_DQ<6>")
	)
	(segment
		(start 301.929546 -230.27005)
		(end 301.746666 -230.08717)
		(width 0.18288)
		(layer "In6.Cu")
		(net "M_C_CPU0_SB_DQ<6>")
	)
	(segment
		(start 308.189884 -231.741472)
		(end 307.551328 -231.741472)
		(width 0.18288)
		(layer "In6.Cu")
		(net "M_C_CPU0_SB_DQ<6>")
	)
	(segment
		(start 296.757852 -230.041196)
		(end 296.416984 -230.041196)
		(width 0.18288)
		(layer "In6.Cu")
		(net "M_C_CPU0_SB_DQ<6>")
	)
	(segment
		(start 337.227164 -240.983008)
		(end 337.212432 -240.991644)
		(width 0.088646)
		(layer "In6.Cu")
		(net "M_C_CPU0_SB_DQ<6>")
	)
	(segment
		(start 336.287364 -240.983008)
		(end 336.272632 -240.991644)
		(width 0.088646)
		(layer "In6.Cu")
		(net "M_C_CPU0_SB_DQ<6>")
	)
	(segment
		(start 332.59649 -240.915952)
		(end 331.723492 -240.042954)
		(width 0.088646)
		(layer "In6.Cu")
		(net "M_C_CPU0_SB_DQ<6>")
	)
	(segment
		(start 331.029564 -239.306354)
		(end 320.174112 -239.306354)
		(width 0.18288)
		(layer "In6.Cu")
		(net "M_C_CPU0_SB_DQ<6>")
	)
	(segment
		(start 292.642544 -228.456998)
		(end 292.482524 -228.617018)
		(width 0.18288)
		(layer "In6.Cu")
		(net "M_C_CPU0_SB_DQ<6>")
	)
	(segment
		(start 301.055786 -229.872032)
		(end 301.055786 -230.08717)
		(width 0.18288)
		(layer "In6.Cu")
		(net "M_C_CPU0_SB_DQ<6>")
	)
	(segment
		(start 297.771312 -230.041196)
		(end 297.611292 -229.881176)
		(width 0.18288)
		(layer "In6.Cu")
		(net "M_C_CPU0_SB_DQ<6>")
	)
	(segment
		(start 331.640688 -239.620298)
		(end 331.326744 -239.306354)
		(width 0.088646)
		(layer "In6.Cu")
		(net "M_C_CPU0_SB_DQ<6>")
	)
	(segment
		(start 301.238666 -229.689152)
		(end 301.055786 -229.872032)
		(width 0.18288)
		(layer "In6.Cu")
		(net "M_C_CPU0_SB_DQ<6>")
	)
	(segment
		(start 345.01328 -241.481102)
		(end 344.700606 -241.481102)
		(width 0.088646)
		(layer "In6.Cu")
		(net "M_C_CPU0_SB_DQ<6>")
	)
	(segment
		(start 288.79673 -227.74275)
		(end 287.575244 -226.521264)
		(width 0.18288)
		(layer "In6.Cu")
		(net "M_C_CPU0_SB_DQ<6>")
	)
	(segment
		(start 305.06797 -230.936546)
		(end 304.88509 -231.119426)
		(width 0.18288)
		(layer "In6.Cu")
		(net "M_C_CPU0_SB_DQ<6>")
	)
	(segment
		(start 297.077892 -229.422452)
		(end 296.917872 -229.582472)
		(width 0.18288)
		(layer "In6.Cu")
		(net "M_C_CPU0_SB_DQ<6>")
	)
	(segment
		(start 296.416984 -230.041196)
		(end 295.567354 -229.191566)
		(width 0.18288)
		(layer "In6.Cu")
		(net "M_C_CPU0_SB_DQ<6>")
	)
	(segment
		(start 308.47919 -231.452166)
		(end 308.189884 -231.741472)
		(width 0.18288)
		(layer "In6.Cu")
		(net "M_C_CPU0_SB_DQ<6>")
	)
	(segment
		(start 292.482524 -228.617018)
		(end 292.1635 -228.617018)
		(width 0.18288)
		(layer "In6.Cu")
		(net "M_C_CPU0_SB_DQ<6>")
	)
	(segment
		(start 286.362648 -225.978974)
		(end 284.529276 -225.978974)
		(width 0.18288)
		(layer "In6.Cu")
		(net "M_C_CPU0_SB_DQ<6>")
	)
	(segment
		(start 340.986364 -240.983008)
		(end 340.971632 -240.991644)
		(width 0.088646)
		(layer "In6.Cu")
		(net "M_C_CPU0_SB_DQ<6>")
	)
	(segment
		(start 290.923726 -228.306884)
		(end 290.359592 -227.74275)
		(width 0.18288)
		(layer "In6.Cu")
		(net "M_C_CPU0_SB_DQ<6>")
	)
	(segment
		(start 297.611292 -229.881176)
		(end 297.611292 -229.582472)
		(width 0.18288)
		(layer "In6.Cu")
		(net "M_C_CPU0_SB_DQ<6>")
	)
	(segment
		(start 342.865964 -240.983008)
		(end 342.851232 -240.991644)
		(width 0.088646)
		(layer "In6.Cu")
		(net "M_C_CPU0_SB_DQ<6>")
	)
	(segment
		(start 301.746666 -230.08717)
		(end 301.746666 -229.872032)
		(width 0.18288)
		(layer "In6.Cu")
		(net "M_C_CPU0_SB_DQ<6>")
	)
	(segment
		(start 313.931808 -234.490514)
		(end 312.198766 -232.757472)
		(width 0.18288)
		(layer "In6.Cu")
		(net "M_C_CPU0_SB_DQ<6>")
	)
	(segment
		(start 305.57597 -230.423466)
		(end 305.25085 -230.423466)
		(width 0.18288)
		(layer "In6.Cu")
		(net "M_C_CPU0_SB_DQ<6>")
	)
	(segment
		(start 306.929282 -231.119426)
		(end 305.94173 -231.119426)
		(width 0.18288)
		(layer "In6.Cu")
		(net "M_C_CPU0_SB_DQ<6>")
	)
	(segment
		(start 294.465248 -229.191566)
		(end 293.294562 -228.02088)
		(width 0.18288)
		(layer "In6.Cu")
		(net "M_C_CPU0_SB_DQ<6>")
	)
	(segment
		(start 311.777634 -232.757472)
		(end 310.761634 -231.741472)
		(width 0.18288)
		(layer "In6.Cu")
		(net "M_C_CPU0_SB_DQ<6>")
	)
	(segment
		(start 307.551328 -231.741472)
		(end 306.929282 -231.119426)
		(width 0.18288)
		(layer "In6.Cu")
		(net "M_C_CPU0_SB_DQ<6>")
	)
	(segment
		(start 299.769276 -230.27005)
		(end 299.540422 -230.041196)
		(width 0.18288)
		(layer "In6.Cu")
		(net "M_C_CPU0_SB_DQ<6>")
	)
	(segment
		(start 331.723492 -239.820196)
		(end 331.640688 -239.620298)
		(width 0.088646)
		(layer "In6.Cu")
		(net "M_C_CPU0_SB_DQ<6>")
	)
	(segment
		(start 301.055786 -230.08717)
		(end 300.872906 -230.27005)
		(width 0.18288)
		(layer "In6.Cu")
		(net "M_C_CPU0_SB_DQ<6>")
	)
	(segment
		(start 315.358272 -234.490514)
		(end 313.931808 -234.490514)
		(width 0.18288)
		(layer "In6.Cu")
		(net "M_C_CPU0_SB_DQ<6>")
	)
	(segment
		(start 304.1523 -231.119426)
		(end 303.302924 -230.27005)
		(width 0.18288)
		(layer "In6.Cu")
		(net "M_C_CPU0_SB_DQ<6>")
	)
	(segment
		(start 286.904938 -226.521264)
		(end 286.362648 -225.978974)
		(width 0.18288)
		(layer "In6.Cu")
		(net "M_C_CPU0_SB_DQ<6>")
	)
	(segment
		(start 312.198766 -232.757472)
		(end 311.777634 -232.757472)
		(width 0.18288)
		(layer "In6.Cu")
		(net "M_C_CPU0_SB_DQ<6>")
	)
	(segment
		(start 339.102192 -240.985548)
		(end 339.091778 -240.991644)
		(width 0.088646)
		(layer "In6.Cu")
		(net "M_C_CPU0_SB_DQ<6>")
	)
	(segment
		(start 297.611292 -229.582472)
		(end 297.451272 -229.422452)
		(width 0.18288)
		(layer "In6.Cu")
		(net "M_C_CPU0_SB_DQ<6>")
	)
	(segment
		(start 331.723492 -240.042954)
		(end 331.723492 -239.820196)
		(width 0.088646)
		(layer "In6.Cu")
		(net "M_C_CPU0_SB_DQ<6>")
	)
	(segment
		(start 331.326744 -239.306354)
		(end 331.029564 -239.306354)
		(width 0.088646)
		(layer "In6.Cu")
		(net "M_C_CPU0_SB_DQ<6>")
	)
	(segment
		(start 301.746666 -229.872032)
		(end 301.563786 -229.689152)
		(width 0.18288)
		(layer "In6.Cu")
		(net "M_C_CPU0_SB_DQ<6>")
	)
	(segment
		(start 320.174112 -239.306354)
		(end 315.358272 -234.490514)
		(width 0.18288)
		(layer "In6.Cu")
		(net "M_C_CPU0_SB_DQ<6>")
	)
	(segment
		(start 305.75885 -230.606346)
		(end 305.57597 -230.423466)
		(width 0.18288)
		(layer "In6.Cu")
		(net "M_C_CPU0_SB_DQ<6>")
	)
	(segment
		(start 309.14721 -231.741472)
		(end 308.857904 -231.452166)
		(width 0.18288)
		(layer "In6.Cu")
		(net "M_C_CPU0_SB_DQ<6>")
	)
	(segment
		(start 310.761634 -231.741472)
		(end 309.14721 -231.741472)
		(width 0.18288)
		(layer "In6.Cu")
		(net "M_C_CPU0_SB_DQ<6>")
	)
	(segment
		(start 291.853366 -228.306884)
		(end 290.923726 -228.306884)
		(width 0.18288)
		(layer "In6.Cu")
		(net "M_C_CPU0_SB_DQ<6>")
	)
	(segment
		(start 305.06797 -230.606346)
		(end 305.06797 -230.936546)
		(width 0.18288)
		(layer "In6.Cu")
		(net "M_C_CPU0_SB_DQ<6>")
	)
	(segment
		(start 304.88509 -231.119426)
		(end 304.1523 -231.119426)
		(width 0.18288)
		(layer "In6.Cu")
		(net "M_C_CPU0_SB_DQ<6>")
	)
	(segment
		(start 332.796134 -240.915952)
		(end 332.59649 -240.915952)
		(width 0.088646)
		(layer "In6.Cu")
		(net "M_C_CPU0_SB_DQ<6>")
	)
	(segment
		(start 300.872906 -230.27005)
		(end 299.769276 -230.27005)
		(width 0.18288)
		(layer "In6.Cu")
		(net "M_C_CPU0_SB_DQ<6>")
	)
	(segment
		(start 292.642544 -228.1809)
		(end 292.642544 -228.456998)
		(width 0.18288)
		(layer "In6.Cu")
		(net "M_C_CPU0_SB_DQ<6>")
	)
	(segment
		(start 303.302924 -230.27005)
		(end 301.929546 -230.27005)
		(width 0.18288)
		(layer "In6.Cu")
		(net "M_C_CPU0_SB_DQ<6>")
	)
	(segment
		(start 308.857904 -231.452166)
		(end 308.47919 -231.452166)
		(width 0.18288)
		(layer "In6.Cu")
		(net "M_C_CPU0_SB_DQ<6>")
	)
	(segment
		(start 344.700606 -241.481102)
		(end 344.635074 -241.41557)
		(width 0.088646)
		(layer "In6.Cu")
		(net "M_C_CPU0_SB_DQ<6>")
	)
	(segment
		(start 338.162646 -240.985548)
		(end 338.152232 -240.991644)
		(width 0.088646)
		(layer "In6.Cu")
		(net "M_C_CPU0_SB_DQ<6>")
	)
	(segment
		(start 287.575244 -226.521264)
		(end 286.904938 -226.521264)
		(width 0.18288)
		(layer "In6.Cu")
		(net "M_C_CPU0_SB_DQ<6>")
	)
	(segment
		(start 305.94173 -231.119426)
		(end 305.75885 -230.936546)
		(width 0.18288)
		(layer "In6.Cu")
		(net "M_C_CPU0_SB_DQ<6>")
	)
	(arc
		(start 339.657436 -240.991644)
		(mid 339.380623 -240.915774)
		(end 339.102192 -240.985548)
		(width 0.088646)
		(layer "In6.Cu")
		(net "M_C_CPU0_SB_DQ<6>")
	)
	(arc
		(start 333.453232 -240.991644)
		(mid 333.266034 -241.041787)
		(end 333.078836 -240.991644)
		(width 0.088646)
		(layer "In6.Cu")
		(net "M_C_CPU0_SB_DQ<6>")
	)
	(arc
		(start 337.777836 -240.991644)
		(mid 337.503637 -240.915809)
		(end 337.227164 -240.983008)
		(width 0.088646)
		(layer "In6.Cu")
		(net "M_C_CPU0_SB_DQ<6>")
	)
	(arc
		(start 342.476836 -240.991644)
		(mid 342.194134 -240.915868)
		(end 341.911432 -240.991644)
		(width 0.088646)
		(layer "In6.Cu")
		(net "M_C_CPU0_SB_DQ<6>")
	)
	(arc
		(start 340.031832 -240.991644)
		(mid 339.844634 -241.041787)
		(end 339.657436 -240.991644)
		(width 0.088646)
		(layer "In6.Cu")
		(net "M_C_CPU0_SB_DQ<6>")
	)
	(arc
		(start 341.537036 -240.991644)
		(mid 341.262837 -240.915809)
		(end 340.986364 -240.983008)
		(width 0.088646)
		(layer "In6.Cu")
		(net "M_C_CPU0_SB_DQ<6>")
	)
	(arc
		(start 335.332832 -240.991644)
		(mid 335.145634 -241.041787)
		(end 334.958436 -240.991644)
		(width 0.088646)
		(layer "In6.Cu")
		(net "M_C_CPU0_SB_DQ<6>")
	)
	(arc
		(start 340.971632 -240.991644)
		(mid 340.784434 -241.041787)
		(end 340.597236 -240.991644)
		(width 0.088646)
		(layer "In6.Cu")
		(net "M_C_CPU0_SB_DQ<6>")
	)
	(arc
		(start 334.958436 -240.991644)
		(mid 334.675734 -240.915868)
		(end 334.393032 -240.991644)
		(width 0.088646)
		(layer "In6.Cu")
		(net "M_C_CPU0_SB_DQ<6>")
	)
	(arc
		(start 337.212432 -240.991644)
		(mid 337.025234 -241.041787)
		(end 336.838036 -240.991644)
		(width 0.088646)
		(layer "In6.Cu")
		(net "M_C_CPU0_SB_DQ<6>")
	)
	(arc
		(start 336.838036 -240.991644)
		(mid 336.563837 -240.915809)
		(end 336.287364 -240.983008)
		(width 0.088646)
		(layer "In6.Cu")
		(net "M_C_CPU0_SB_DQ<6>")
	)
	(arc
		(start 335.898236 -240.991644)
		(mid 335.615534 -240.915868)
		(end 335.332832 -240.991644)
		(width 0.088646)
		(layer "In6.Cu")
		(net "M_C_CPU0_SB_DQ<6>")
	)
	(arc
		(start 343.416636 -240.991644)
		(mid 343.142437 -240.915809)
		(end 342.865964 -240.983008)
		(width 0.088646)
		(layer "In6.Cu")
		(net "M_C_CPU0_SB_DQ<6>")
	)
	(arc
		(start 344.635074 -241.41557)
		(mid 344.545986 -241.170585)
		(end 344.356436 -240.991644)
		(width 0.088646)
		(layer "In6.Cu")
		(net "M_C_CPU0_SB_DQ<6>")
	)
	(arc
		(start 333.078836 -240.991644)
		(mid 332.94247 -240.935166)
		(end 332.796134 -240.915952)
		(width 0.088646)
		(layer "In6.Cu")
		(net "M_C_CPU0_SB_DQ<6>")
	)
	(arc
		(start 336.272632 -240.991644)
		(mid 336.085434 -241.041787)
		(end 335.898236 -240.991644)
		(width 0.088646)
		(layer "In6.Cu")
		(net "M_C_CPU0_SB_DQ<6>")
	)
	(arc
		(start 334.393032 -240.991644)
		(mid 334.205834 -241.041787)
		(end 334.018636 -240.991644)
		(width 0.088646)
		(layer "In6.Cu")
		(net "M_C_CPU0_SB_DQ<6>")
	)
	(arc
		(start 338.717382 -240.991644)
		(mid 338.440823 -240.915901)
		(end 338.162646 -240.985548)
		(width 0.088646)
		(layer "In6.Cu")
		(net "M_C_CPU0_SB_DQ<6>")
	)
	(arc
		(start 334.018636 -240.991644)
		(mid 333.744437 -240.915809)
		(end 333.467964 -240.983008)
		(width 0.088646)
		(layer "In6.Cu")
		(net "M_C_CPU0_SB_DQ<6>")
	)
	(arc
		(start 339.091778 -240.991644)
		(mid 338.90458 -241.041787)
		(end 338.717382 -240.991644)
		(width 0.088646)
		(layer "In6.Cu")
		(net "M_C_CPU0_SB_DQ<6>")
	)
	(arc
		(start 342.851232 -240.991644)
		(mid 342.664034 -241.041787)
		(end 342.476836 -240.991644)
		(width 0.088646)
		(layer "In6.Cu")
		(net "M_C_CPU0_SB_DQ<6>")
	)
	(arc
		(start 341.911432 -240.991644)
		(mid 341.724234 -241.041787)
		(end 341.537036 -240.991644)
		(width 0.088646)
		(layer "In6.Cu")
		(net "M_C_CPU0_SB_DQ<6>")
	)
	(arc
		(start 344.356436 -240.991644)
		(mid 344.082237 -240.915809)
		(end 343.805764 -240.983008)
		(width 0.088646)
		(layer "In6.Cu")
		(net "M_C_CPU0_SB_DQ<6>")
	)
	(arc
		(start 338.152232 -240.991644)
		(mid 337.965034 -241.041787)
		(end 337.777836 -240.991644)
		(width 0.088646)
		(layer "In6.Cu")
		(net "M_C_CPU0_SB_DQ<6>")
	)
	(arc
		(start 340.597236 -240.991644)
		(mid 340.323037 -240.915809)
		(end 340.046564 -240.983008)
		(width 0.088646)
		(layer "In6.Cu")
		(net "M_C_CPU0_SB_DQ<6>")
	)
	(arc
		(start 343.791032 -240.991644)
		(mid 343.603834 -241.041787)
		(end 343.416636 -240.991644)
		(width 0.088646)
		(layer "In6.Cu")
		(net "M_C_CPU0_SB_DQ<6>")
	)
	(segment
		(start 276.647656 -224.091754)
		(end 276.469094 -224.091754)
		(width 0.20066)
		(layer "F.Cu")
		(net "M_C_CPU0_SB_DQ<5>")
	)
	(segment
		(start 343.60358 -241.203226)
		(end 343.603834 -241.202972)
		(width 0.20066)
		(layer "F.Cu")
		(net "M_C_CPU0_SB_DQ<5>")
	)
	(segment
		(start 343.603834 -241.202972)
		(end 343.603834 -240.667286)
		(width 0.20066)
		(layer "F.Cu")
		(net "M_C_CPU0_SB_DQ<5>")
	)
	(segment
		(start 273.218148 -224.728024)
		(end 272.713704 -224.728024)
		(width 0.20066)
		(layer "F.Cu")
		(net "M_C_CPU0_SB_DQ<5>")
	)
	(segment
		(start 277.072598 -224.516696)
		(end 276.647656 -224.091754)
		(width 0.20066)
		(layer "F.Cu")
		(net "M_C_CPU0_SB_DQ<5>")
	)
	(segment
		(start 274.143978 -224.082864)
		(end 273.53514 -224.082864)
		(width 0.20066)
		(layer "F.Cu")
		(net "M_C_CPU0_SB_DQ<5>")
	)
	(segment
		(start 278.711914 -224.516696)
		(end 277.072598 -224.516696)
		(width 0.20066)
		(layer "F.Cu")
		(net "M_C_CPU0_SB_DQ<5>")
	)
	(segment
		(start 272.502376 -224.516696)
		(end 271.168114 -224.516696)
		(width 0.20066)
		(layer "F.Cu")
		(net "M_C_CPU0_SB_DQ<5>")
	)
	(segment
		(start 274.152868 -224.091754)
		(end 274.143978 -224.082864)
		(width 0.1016)
		(layer "F.Cu")
		(net "M_C_CPU0_SB_DQ<5>")
	)
	(segment
		(start 273.53514 -224.082864)
		(end 273.37258 -224.245424)
		(width 0.20066)
		(layer "F.Cu")
		(net "M_C_CPU0_SB_DQ<5>")
	)
	(segment
		(start 279.816814 -224.516696)
		(end 278.711914 -224.516696)
		(width 0.20066)
		(layer "F.Cu")
		(net "M_C_CPU0_SB_DQ<5>")
	)
	(segment
		(start 273.37258 -224.573592)
		(end 273.218148 -224.728024)
		(width 0.20066)
		(layer "F.Cu")
		(net "M_C_CPU0_SB_DQ<5>")
	)
	(segment
		(start 272.713704 -224.728024)
		(end 272.502376 -224.516696)
		(width 0.20066)
		(layer "F.Cu")
		(net "M_C_CPU0_SB_DQ<5>")
	)
	(segment
		(start 276.469094 -224.091754)
		(end 276.138386 -224.091754)
		(width 0.101854)
		(layer "F.Cu")
		(net "M_C_CPU0_SB_DQ<5>")
	)
	(segment
		(start 276.138386 -224.091754)
		(end 274.152868 -224.091754)
		(width 0.1016)
		(layer "F.Cu")
		(net "M_C_CPU0_SB_DQ<5>")
	)
	(segment
		(start 273.37258 -224.245424)
		(end 273.37258 -224.573592)
		(width 0.20066)
		(layer "F.Cu")
		(net "M_C_CPU0_SB_DQ<5>")
	)
	(segment
		(start 343.916508 -240.667286)
		(end 343.973912 -240.609882)
		(width 0.088646)
		(layer "In6.Cu")
		(net "M_C_CPU0_SB_DQ<5>")
	)
	(segment
		(start 312.002678 -231.613456)
		(end 311.48782 -231.613456)
		(width 0.18288)
		(layer "In6.Cu")
		(net "M_C_CPU0_SB_DQ<5>")
	)
	(segment
		(start 287.779714 -226.00031)
		(end 287.140396 -226.00031)
		(width 0.18288)
		(layer "In6.Cu")
		(net "M_C_CPU0_SB_DQ<5>")
	)
	(segment
		(start 287.140396 -226.00031)
		(end 286.555942 -225.415856)
		(width 0.18288)
		(layer "In6.Cu")
		(net "M_C_CPU0_SB_DQ<5>")
	)
	(segment
		(start 303.888648 -229.925626)
		(end 303.154334 -229.191312)
		(width 0.18288)
		(layer "In6.Cu")
		(net "M_C_CPU0_SB_DQ<5>")
	)
	(segment
		(start 333.077312 -240.342928)
		(end 333.066898 -240.349024)
		(width 0.088646)
		(layer "In6.Cu")
		(net "M_C_CPU0_SB_DQ<5>")
	)
	(segment
		(start 285.437072 -224.941384)
		(end 280.241502 -224.941384)
		(width 0.18288)
		(layer "In6.Cu")
		(net "M_C_CPU0_SB_DQ<5>")
	)
	(segment
		(start 341.926164 -240.351564)
		(end 341.911432 -240.342928)
		(width 0.088646)
		(layer "In6.Cu")
		(net "M_C_CPU0_SB_DQ<5>")
	)
	(segment
		(start 339.102192 -240.349024)
		(end 339.091778 -240.342928)
		(width 0.088646)
		(layer "In6.Cu")
		(net "M_C_CPU0_SB_DQ<5>")
	)
	(segment
		(start 332.39456 -240.253266)
		(end 331.961744 -239.82045)
		(width 0.088646)
		(layer "In6.Cu")
		(net "M_C_CPU0_SB_DQ<5>")
	)
	(segment
		(start 337.227164 -240.351564)
		(end 337.212432 -240.342928)
		(width 0.088646)
		(layer "In6.Cu")
		(net "M_C_CPU0_SB_DQ<5>")
	)
	(segment
		(start 340.046564 -240.351564)
		(end 340.031832 -240.342928)
		(width 0.088646)
		(layer "In6.Cu")
		(net "M_C_CPU0_SB_DQ<5>")
	)
	(segment
		(start 288.992564 -227.21316)
		(end 287.779714 -226.00031)
		(width 0.18288)
		(layer "In6.Cu")
		(net "M_C_CPU0_SB_DQ<5>")
	)
	(segment
		(start 296.475658 -227.49129)
		(end 291.131498 -227.49129)
		(width 0.18288)
		(layer "In6.Cu")
		(net "M_C_CPU0_SB_DQ<5>")
	)
	(segment
		(start 331.218032 -238.801148)
		(end 331.029564 -238.801148)
		(width 0.088646)
		(layer "In6.Cu")
		(net "M_C_CPU0_SB_DQ<5>")
	)
	(segment
		(start 342.865964 -240.351564)
		(end 342.851232 -240.342928)
		(width 0.088646)
		(layer "In6.Cu")
		(net "M_C_CPU0_SB_DQ<5>")
	)
	(segment
		(start 334.017366 -240.342928)
		(end 334.006952 -240.349024)
		(width 0.088646)
		(layer "In6.Cu")
		(net "M_C_CPU0_SB_DQ<5>")
	)
	(segment
		(start 310.765952 -230.891588)
		(end 308.349396 -230.891588)
		(width 0.18288)
		(layer "In6.Cu")
		(net "M_C_CPU0_SB_DQ<5>")
	)
	(segment
		(start 331.961744 -239.82045)
		(end 331.766672 -239.349788)
		(width 0.088646)
		(layer "In6.Cu")
		(net "M_C_CPU0_SB_DQ<5>")
	)
	(segment
		(start 314.89269 -233.28884)
		(end 313.678062 -233.28884)
		(width 0.18288)
		(layer "In6.Cu")
		(net "M_C_CPU0_SB_DQ<5>")
	)
	(segment
		(start 286.555942 -225.415856)
		(end 285.911544 -225.415856)
		(width 0.18288)
		(layer "In6.Cu")
		(net "M_C_CPU0_SB_DQ<5>")
	)
	(segment
		(start 298.17568 -229.191312)
		(end 296.475658 -227.49129)
		(width 0.18288)
		(layer "In6.Cu")
		(net "M_C_CPU0_SB_DQ<5>")
	)
	(segment
		(start 334.029304 -240.33607)
		(end 334.017366 -240.342928)
		(width 0.088646)
		(layer "In6.Cu")
		(net "M_C_CPU0_SB_DQ<5>")
	)
	(segment
		(start 331.766672 -239.349788)
		(end 331.218032 -238.801148)
		(width 0.088646)
		(layer "In6.Cu")
		(net "M_C_CPU0_SB_DQ<5>")
	)
	(segment
		(start 290.853368 -227.21316)
		(end 288.992564 -227.21316)
		(width 0.18288)
		(layer "In6.Cu")
		(net "M_C_CPU0_SB_DQ<5>")
	)
	(segment
		(start 303.154334 -229.191312)
		(end 298.17568 -229.191312)
		(width 0.18288)
		(layer "In6.Cu")
		(net "M_C_CPU0_SB_DQ<5>")
	)
	(segment
		(start 343.799922 -240.348008)
		(end 343.791032 -240.342928)
		(width 0.088646)
		(layer "In6.Cu")
		(net "M_C_CPU0_SB_DQ<5>")
	)
	(segment
		(start 311.48782 -231.613456)
		(end 310.765952 -230.891588)
		(width 0.18288)
		(layer "In6.Cu")
		(net "M_C_CPU0_SB_DQ<5>")
	)
	(segment
		(start 291.131498 -227.49129)
		(end 290.853368 -227.21316)
		(width 0.18288)
		(layer "In6.Cu")
		(net "M_C_CPU0_SB_DQ<5>")
	)
	(segment
		(start 336.287364 -240.351564)
		(end 336.272632 -240.342928)
		(width 0.088646)
		(layer "In6.Cu")
		(net "M_C_CPU0_SB_DQ<5>")
	)
	(segment
		(start 338.717382 -240.342928)
		(end 338.706968 -240.349024)
		(width 0.088646)
		(layer "In6.Cu")
		(net "M_C_CPU0_SB_DQ<5>")
	)
	(segment
		(start 340.986364 -240.351564)
		(end 340.971632 -240.342928)
		(width 0.088646)
		(layer "In6.Cu")
		(net "M_C_CPU0_SB_DQ<5>")
	)
	(segment
		(start 307.383434 -229.925626)
		(end 303.888648 -229.925626)
		(width 0.18288)
		(layer "In6.Cu")
		(net "M_C_CPU0_SB_DQ<5>")
	)
	(segment
		(start 320.404998 -238.801148)
		(end 314.89269 -233.28884)
		(width 0.18288)
		(layer "In6.Cu")
		(net "M_C_CPU0_SB_DQ<5>")
	)
	(segment
		(start 334.966056 -240.338102)
		(end 334.957674 -240.342928)
		(width 0.088646)
		(layer "In6.Cu")
		(net "M_C_CPU0_SB_DQ<5>")
	)
	(segment
		(start 285.911544 -225.415856)
		(end 285.437072 -224.941384)
		(width 0.18288)
		(layer "In6.Cu")
		(net "M_C_CPU0_SB_DQ<5>")
	)
	(segment
		(start 308.349396 -230.891588)
		(end 307.383434 -229.925626)
		(width 0.18288)
		(layer "In6.Cu")
		(net "M_C_CPU0_SB_DQ<5>")
	)
	(segment
		(start 334.957674 -240.342928)
		(end 334.936846 -240.35512)
		(width 0.088646)
		(layer "In6.Cu")
		(net "M_C_CPU0_SB_DQ<5>")
	)
	(segment
		(start 336.272632 -240.342928)
		(end 336.26425 -240.338102)
		(width 0.088646)
		(layer "In6.Cu")
		(net "M_C_CPU0_SB_DQ<5>")
	)
	(segment
		(start 313.678062 -233.28884)
		(end 312.002678 -231.613456)
		(width 0.18288)
		(layer "In6.Cu")
		(net "M_C_CPU0_SB_DQ<5>")
	)
	(segment
		(start 343.603834 -240.667286)
		(end 343.916508 -240.667286)
		(width 0.088646)
		(layer "In6.Cu")
		(net "M_C_CPU0_SB_DQ<5>")
	)
	(segment
		(start 331.029564 -238.801148)
		(end 320.404998 -238.801148)
		(width 0.18288)
		(layer "In6.Cu")
		(net "M_C_CPU0_SB_DQ<5>")
	)
	(segment
		(start 335.34223 -240.349024)
		(end 335.331816 -240.342928)
		(width 0.088646)
		(layer "In6.Cu")
		(net "M_C_CPU0_SB_DQ<5>")
	)
	(segment
		(start 280.241502 -224.941384)
		(end 279.816814 -224.516696)
		(width 0.18288)
		(layer "In6.Cu")
		(net "M_C_CPU0_SB_DQ<5>")
	)
	(arc
		(start 340.031832 -240.342928)
		(mid 339.844634 -240.292785)
		(end 339.657436 -240.342928)
		(width 0.088646)
		(layer "In6.Cu")
		(net "M_C_CPU0_SB_DQ<5>")
	)
	(arc
		(start 335.331816 -240.342928)
		(mid 335.149565 -240.292817)
		(end 334.966056 -240.338102)
		(width 0.088646)
		(layer "In6.Cu")
		(net "M_C_CPU0_SB_DQ<5>")
	)
	(arc
		(start 338.152232 -240.342928)
		(mid 337.965034 -240.292785)
		(end 337.777836 -240.342928)
		(width 0.088646)
		(layer "In6.Cu")
		(net "M_C_CPU0_SB_DQ<5>")
	)
	(arc
		(start 341.911432 -240.342928)
		(mid 341.724234 -240.292785)
		(end 341.537036 -240.342928)
		(width 0.088646)
		(layer "In6.Cu")
		(net "M_C_CPU0_SB_DQ<5>")
	)
	(arc
		(start 334.006952 -240.349024)
		(mid 333.72852 -240.418838)
		(end 333.451708 -240.342928)
		(width 0.088646)
		(layer "In6.Cu")
		(net "M_C_CPU0_SB_DQ<5>")
	)
	(arc
		(start 337.212432 -240.342928)
		(mid 337.025234 -240.292785)
		(end 336.838036 -240.342928)
		(width 0.088646)
		(layer "In6.Cu")
		(net "M_C_CPU0_SB_DQ<5>")
	)
	(arc
		(start 340.971632 -240.342928)
		(mid 340.784434 -240.292785)
		(end 340.597236 -240.342928)
		(width 0.088646)
		(layer "In6.Cu")
		(net "M_C_CPU0_SB_DQ<5>")
	)
	(arc
		(start 336.26425 -240.338102)
		(mid 336.080488 -240.292702)
		(end 335.897982 -240.342928)
		(width 0.088646)
		(layer "In6.Cu")
		(net "M_C_CPU0_SB_DQ<5>")
	)
	(arc
		(start 342.476836 -240.342928)
		(mid 342.202607 -240.418853)
		(end 341.926164 -240.351564)
		(width 0.088646)
		(layer "In6.Cu")
		(net "M_C_CPU0_SB_DQ<5>")
	)
	(arc
		(start 334.936846 -240.35512)
		(mid 334.663004 -240.418835)
		(end 334.39227 -240.342928)
		(width 0.088646)
		(layer "In6.Cu")
		(net "M_C_CPU0_SB_DQ<5>")
	)
	(arc
		(start 333.066898 -240.349024)
		(mid 332.788466 -240.418838)
		(end 332.511654 -240.342928)
		(width 0.088646)
		(layer "In6.Cu")
		(net "M_C_CPU0_SB_DQ<5>")
	)
	(arc
		(start 332.511654 -240.342928)
		(mid 332.450169 -240.301933)
		(end 332.39456 -240.253266)
		(width 0.088646)
		(layer "In6.Cu")
		(net "M_C_CPU0_SB_DQ<5>")
	)
	(arc
		(start 343.973912 -240.609882)
		(mid 343.915756 -240.459769)
		(end 343.799922 -240.348008)
		(width 0.088646)
		(layer "In6.Cu")
		(net "M_C_CPU0_SB_DQ<5>")
	)
	(arc
		(start 339.657436 -240.342928)
		(mid 339.380623 -240.418764)
		(end 339.102192 -240.349024)
		(width 0.088646)
		(layer "In6.Cu")
		(net "M_C_CPU0_SB_DQ<5>")
	)
	(arc
		(start 342.851232 -240.342928)
		(mid 342.664034 -240.292785)
		(end 342.476836 -240.342928)
		(width 0.088646)
		(layer "In6.Cu")
		(net "M_C_CPU0_SB_DQ<5>")
	)
	(arc
		(start 343.791032 -240.342928)
		(mid 343.603834 -240.292785)
		(end 343.416636 -240.342928)
		(width 0.088646)
		(layer "In6.Cu")
		(net "M_C_CPU0_SB_DQ<5>")
	)
	(arc
		(start 340.597236 -240.342928)
		(mid 340.323007 -240.418853)
		(end 340.046564 -240.351564)
		(width 0.088646)
		(layer "In6.Cu")
		(net "M_C_CPU0_SB_DQ<5>")
	)
	(arc
		(start 337.777836 -240.342928)
		(mid 337.503607 -240.418853)
		(end 337.227164 -240.351564)
		(width 0.088646)
		(layer "In6.Cu")
		(net "M_C_CPU0_SB_DQ<5>")
	)
	(arc
		(start 339.091778 -240.342928)
		(mid 338.90458 -240.292785)
		(end 338.717382 -240.342928)
		(width 0.088646)
		(layer "In6.Cu")
		(net "M_C_CPU0_SB_DQ<5>")
	)
	(arc
		(start 334.39227 -240.342928)
		(mid 334.211669 -240.292598)
		(end 334.029304 -240.33607)
		(width 0.088646)
		(layer "In6.Cu")
		(net "M_C_CPU0_SB_DQ<5>")
	)
	(arc
		(start 335.897982 -240.342928)
		(mid 335.620915 -240.418891)
		(end 335.34223 -240.349024)
		(width 0.088646)
		(layer "In6.Cu")
		(net "M_C_CPU0_SB_DQ<5>")
	)
	(arc
		(start 343.416636 -240.342928)
		(mid 343.142407 -240.418853)
		(end 342.865964 -240.351564)
		(width 0.088646)
		(layer "In6.Cu")
		(net "M_C_CPU0_SB_DQ<5>")
	)
	(arc
		(start 338.706968 -240.349024)
		(mid 338.42879 -240.418716)
		(end 338.152232 -240.342928)
		(width 0.088646)
		(layer "In6.Cu")
		(net "M_C_CPU0_SB_DQ<5>")
	)
	(arc
		(start 341.537036 -240.342928)
		(mid 341.262807 -240.418853)
		(end 340.986364 -240.351564)
		(width 0.088646)
		(layer "In6.Cu")
		(net "M_C_CPU0_SB_DQ<5>")
	)
	(arc
		(start 336.838036 -240.342928)
		(mid 336.563807 -240.418853)
		(end 336.287364 -240.351564)
		(width 0.088646)
		(layer "In6.Cu")
		(net "M_C_CPU0_SB_DQ<5>")
	)
	(arc
		(start 333.451708 -240.342928)
		(mid 333.26451 -240.292785)
		(end 333.077312 -240.342928)
		(width 0.088646)
		(layer "In6.Cu")
		(net "M_C_CPU0_SB_DQ<5>")
	)
	(segment
		(start 343.133934 -242.017042)
		(end 343.13368 -242.016788)
		(width 0.20066)
		(layer "F.Cu")
		(net "M_C_CPU0_SB_DQ<4>")
	)
	(segment
		(start 272.741136 -226.455478)
		(end 272.502376 -226.216718)
		(width 0.20066)
		(layer "F.Cu")
		(net "M_C_CPU0_SB_DQ<4>")
	)
	(segment
		(start 276.469094 -225.791776)
		(end 274.40001 -225.791776)
		(width 0.1016)
		(layer "F.Cu")
		(net "M_C_CPU0_SB_DQ<4>")
	)
	(segment
		(start 343.13368 -242.016788)
		(end 343.13368 -241.481102)
		(width 0.20066)
		(layer "F.Cu")
		(net "M_C_CPU0_SB_DQ<4>")
	)
	(segment
		(start 273.37258 -226.282758)
		(end 273.19986 -226.455478)
		(width 0.20066)
		(layer "F.Cu")
		(net "M_C_CPU0_SB_DQ<4>")
	)
	(segment
		(start 279.816814 -226.216718)
		(end 278.711914 -226.216718)
		(width 0.20066)
		(layer "F.Cu")
		(net "M_C_CPU0_SB_DQ<4>")
	)
	(segment
		(start 274.143978 -225.783648)
		(end 273.58213 -225.783648)
		(width 0.20066)
		(layer "F.Cu")
		(net "M_C_CPU0_SB_DQ<4>")
	)
	(segment
		(start 278.711914 -226.216718)
		(end 277.342854 -226.216718)
		(width 0.20066)
		(layer "F.Cu")
		(net "M_C_CPU0_SB_DQ<4>")
	)
	(segment
		(start 277.342854 -226.216718)
		(end 276.917912 -225.791776)
		(width 0.20066)
		(layer "F.Cu")
		(net "M_C_CPU0_SB_DQ<4>")
	)
	(segment
		(start 276.917912 -225.791776)
		(end 276.469094 -225.791776)
		(width 0.20066)
		(layer "F.Cu")
		(net "M_C_CPU0_SB_DQ<4>")
	)
	(segment
		(start 273.58213 -225.783648)
		(end 273.37258 -225.993198)
		(width 0.20066)
		(layer "F.Cu")
		(net "M_C_CPU0_SB_DQ<4>")
	)
	(segment
		(start 273.19986 -226.455478)
		(end 272.741136 -226.455478)
		(width 0.20066)
		(layer "F.Cu")
		(net "M_C_CPU0_SB_DQ<4>")
	)
	(segment
		(start 273.37258 -225.993198)
		(end 273.37258 -226.282758)
		(width 0.20066)
		(layer "F.Cu")
		(net "M_C_CPU0_SB_DQ<4>")
	)
	(segment
		(start 274.152106 -225.791776)
		(end 274.143978 -225.783648)
		(width 0.101854)
		(layer "F.Cu")
		(net "M_C_CPU0_SB_DQ<4>")
	)
	(segment
		(start 272.502376 -226.216718)
		(end 271.168114 -226.216718)
		(width 0.20066)
		(layer "F.Cu")
		(net "M_C_CPU0_SB_DQ<4>")
	)
	(segment
		(start 274.40001 -225.791776)
		(end 274.152106 -225.791776)
		(width 0.101854)
		(layer "F.Cu")
		(net "M_C_CPU0_SB_DQ<4>")
	)
	(segment
		(start 288.052002 -227.835714)
		(end 287.326578 -227.835714)
		(width 0.18288)
		(layer "In6.Cu")
		(net "M_C_CPU0_SB_DQ<4>")
	)
	(segment
		(start 341.066882 -241.156744)
		(end 341.05215 -241.16538)
		(width 0.088646)
		(layer "In6.Cu")
		(net "M_C_CPU0_SB_DQ<4>")
	)
	(segment
		(start 281.805634 -226.823778)
		(end 281.805634 -227.065078)
		(width 0.18288)
		(layer "In6.Cu")
		(net "M_C_CPU0_SB_DQ<4>")
	)
	(segment
		(start 287.326578 -227.835714)
		(end 286.131762 -226.640898)
		(width 0.18288)
		(layer "In6.Cu")
		(net "M_C_CPU0_SB_DQ<4>")
	)
	(segment
		(start 338.247482 -241.156744)
		(end 338.23275 -241.16538)
		(width 0.088646)
		(layer "In6.Cu")
		(net "M_C_CPU0_SB_DQ<4>")
	)
	(segment
		(start 333.548482 -241.156744)
		(end 333.53375 -241.16538)
		(width 0.088646)
		(layer "In6.Cu")
		(net "M_C_CPU0_SB_DQ<4>")
	)
	(segment
		(start 286.131762 -226.640898)
		(end 283.370274 -226.640898)
		(width 0.18288)
		(layer "In6.Cu")
		(net "M_C_CPU0_SB_DQ<4>")
	)
	(segment
		(start 282.496514 -227.065078)
		(end 282.496514 -226.823778)
		(width 0.18288)
		(layer "In6.Cu")
		(net "M_C_CPU0_SB_DQ<4>")
	)
	(segment
		(start 292.915848 -229.192328)
		(end 290.444428 -229.192328)
		(width 0.18288)
		(layer "In6.Cu")
		(net "M_C_CPU0_SB_DQ<4>")
	)
	(segment
		(start 289.57143 -228.31933)
		(end 288.535618 -228.31933)
		(width 0.18288)
		(layer "In6.Cu")
		(net "M_C_CPU0_SB_DQ<4>")
	)
	(segment
		(start 319.96634 -239.804956)
		(end 315.166756 -235.005372)
		(width 0.18288)
		(layer "In6.Cu")
		(net "M_C_CPU0_SB_DQ<4>")
	)
	(segment
		(start 342.006936 -241.156744)
		(end 341.996522 -241.16284)
		(width 0.088646)
		(layer "In6.Cu")
		(net "M_C_CPU0_SB_DQ<4>")
	)
	(segment
		(start 319.96634 -239.80775)
		(end 319.96634 -239.804956)
		(width 0.18288)
		(layer "In6.Cu")
		(net "M_C_CPU0_SB_DQ<4>")
	)
	(segment
		(start 313.737498 -235.005372)
		(end 312.105294 -233.373168)
		(width 0.18288)
		(layer "In6.Cu")
		(net "M_C_CPU0_SB_DQ<4>")
	)
	(segment
		(start 281.622754 -227.247958)
		(end 281.297634 -227.247958)
		(width 0.18288)
		(layer "In6.Cu")
		(net "M_C_CPU0_SB_DQ<4>")
	)
	(segment
		(start 282.496514 -226.823778)
		(end 282.313634 -226.640898)
		(width 0.18288)
		(layer "In6.Cu")
		(net "M_C_CPU0_SB_DQ<4>")
	)
	(segment
		(start 281.988514 -226.640898)
		(end 281.805634 -226.823778)
		(width 0.18288)
		(layer "In6.Cu")
		(net "M_C_CPU0_SB_DQ<4>")
	)
	(segment
		(start 280.931874 -226.640898)
		(end 280.240994 -226.640898)
		(width 0.18288)
		(layer "In6.Cu")
		(net "M_C_CPU0_SB_DQ<4>")
	)
	(segment
		(start 281.114754 -226.823778)
		(end 280.931874 -226.640898)
		(width 0.18288)
		(layer "In6.Cu")
		(net "M_C_CPU0_SB_DQ<4>")
	)
	(segment
		(start 340.127082 -241.156744)
		(end 340.11235 -241.16538)
		(width 0.088646)
		(layer "In6.Cu")
		(net "M_C_CPU0_SB_DQ<4>")
	)
	(segment
		(start 283.187394 -226.823778)
		(end 283.187394 -227.065078)
		(width 0.18288)
		(layer "In6.Cu")
		(net "M_C_CPU0_SB_DQ<4>")
	)
	(segment
		(start 306.732178 -231.652826)
		(end 303.725834 -231.652826)
		(width 0.18288)
		(layer "In6.Cu")
		(net "M_C_CPU0_SB_DQ<4>")
	)
	(segment
		(start 282.313634 -226.640898)
		(end 281.988514 -226.640898)
		(width 0.18288)
		(layer "In6.Cu")
		(net "M_C_CPU0_SB_DQ<4>")
	)
	(segment
		(start 310.69661 -232.59161)
		(end 307.670962 -232.59161)
		(width 0.18288)
		(layer "In6.Cu")
		(net "M_C_CPU0_SB_DQ<4>")
	)
	(segment
		(start 342.61933 -241.231166)
		(end 342.59647 -241.228372)
		(width 0.088646)
		(layer "In6.Cu")
		(net "M_C_CPU0_SB_DQ<4>")
	)
	(segment
		(start 283.004514 -227.247958)
		(end 282.679394 -227.247958)
		(width 0.18288)
		(layer "In6.Cu")
		(net "M_C_CPU0_SB_DQ<4>")
	)
	(segment
		(start 281.297634 -227.247958)
		(end 281.114754 -227.065078)
		(width 0.18288)
		(layer "In6.Cu")
		(net "M_C_CPU0_SB_DQ<4>")
	)
	(segment
		(start 303.725834 -231.652826)
		(end 302.964342 -230.891334)
		(width 0.18288)
		(layer "In6.Cu")
		(net "M_C_CPU0_SB_DQ<4>")
	)
	(segment
		(start 281.114754 -227.065078)
		(end 281.114754 -226.823778)
		(width 0.18288)
		(layer "In6.Cu")
		(net "M_C_CPU0_SB_DQ<4>")
	)
	(segment
		(start 336.367882 -241.156744)
		(end 336.357468 -241.16284)
		(width 0.088646)
		(layer "In6.Cu")
		(net "M_C_CPU0_SB_DQ<4>")
	)
	(segment
		(start 296.556176 -230.891334)
		(end 295.706546 -230.041704)
		(width 0.18288)
		(layer "In6.Cu")
		(net "M_C_CPU0_SB_DQ<4>")
	)
	(segment
		(start 283.370274 -226.640898)
		(end 283.187394 -226.823778)
		(width 0.18288)
		(layer "In6.Cu")
		(net "M_C_CPU0_SB_DQ<4>")
	)
	(segment
		(start 290.444428 -229.192328)
		(end 289.57143 -228.31933)
		(width 0.18288)
		(layer "In6.Cu")
		(net "M_C_CPU0_SB_DQ<4>")
	)
	(segment
		(start 337.307682 -241.156744)
		(end 337.29295 -241.16538)
		(width 0.088646)
		(layer "In6.Cu")
		(net "M_C_CPU0_SB_DQ<4>")
	)
	(segment
		(start 315.166756 -235.005372)
		(end 313.737498 -235.005372)
		(width 0.18288)
		(layer "In6.Cu")
		(net "M_C_CPU0_SB_DQ<4>")
	)
	(segment
		(start 332.796134 -241.106198)
		(end 332.517496 -241.106198)
		(width 0.088646)
		(layer "In6.Cu")
		(net "M_C_CPU0_SB_DQ<4>")
	)
	(segment
		(start 331.510132 -239.99063)
		(end 331.327252 -239.80775)
		(width 0.088646)
		(layer "In6.Cu")
		(net "M_C_CPU0_SB_DQ<4>")
	)
	(segment
		(start 293.765224 -230.041704)
		(end 292.915848 -229.192328)
		(width 0.18288)
		(layer "In6.Cu")
		(net "M_C_CPU0_SB_DQ<4>")
	)
	(segment
		(start 331.510132 -240.098834)
		(end 331.510132 -239.99063)
		(width 0.088646)
		(layer "In6.Cu")
		(net "M_C_CPU0_SB_DQ<4>")
	)
	(segment
		(start 307.670962 -232.59161)
		(end 306.732178 -231.652826)
		(width 0.18288)
		(layer "In6.Cu")
		(net "M_C_CPU0_SB_DQ<4>")
	)
	(segment
		(start 332.517496 -241.106198)
		(end 331.510132 -240.098834)
		(width 0.088646)
		(layer "In6.Cu")
		(net "M_C_CPU0_SB_DQ<4>")
	)
	(segment
		(start 288.535618 -228.31933)
		(end 288.052002 -227.835714)
		(width 0.18288)
		(layer "In6.Cu")
		(net "M_C_CPU0_SB_DQ<4>")
	)
	(segment
		(start 334.488536 -241.156744)
		(end 334.478122 -241.16284)
		(width 0.088646)
		(layer "In6.Cu")
		(net "M_C_CPU0_SB_DQ<4>")
	)
	(segment
		(start 331.327252 -239.80775)
		(end 331.029564 -239.80775)
		(width 0.088646)
		(layer "In6.Cu")
		(net "M_C_CPU0_SB_DQ<4>")
	)
	(segment
		(start 311.478168 -233.373168)
		(end 310.69661 -232.59161)
		(width 0.18288)
		(layer "In6.Cu")
		(net "M_C_CPU0_SB_DQ<4>")
	)
	(segment
		(start 302.964342 -230.891334)
		(end 296.556176 -230.891334)
		(width 0.18288)
		(layer "In6.Cu")
		(net "M_C_CPU0_SB_DQ<4>")
	)
	(segment
		(start 282.679394 -227.247958)
		(end 282.496514 -227.065078)
		(width 0.18288)
		(layer "In6.Cu")
		(net "M_C_CPU0_SB_DQ<4>")
	)
	(segment
		(start 280.240994 -226.640898)
		(end 279.816814 -226.216718)
		(width 0.18288)
		(layer "In6.Cu")
		(net "M_C_CPU0_SB_DQ<4>")
	)
	(segment
		(start 331.029564 -239.80775)
		(end 319.96634 -239.80775)
		(width 0.18288)
		(layer "In6.Cu")
		(net "M_C_CPU0_SB_DQ<4>")
	)
	(segment
		(start 281.805634 -227.065078)
		(end 281.622754 -227.247958)
		(width 0.18288)
		(layer "In6.Cu")
		(net "M_C_CPU0_SB_DQ<4>")
	)
	(segment
		(start 295.706546 -230.041704)
		(end 293.765224 -230.041704)
		(width 0.18288)
		(layer "In6.Cu")
		(net "M_C_CPU0_SB_DQ<4>")
	)
	(segment
		(start 312.105294 -233.373168)
		(end 311.478168 -233.373168)
		(width 0.18288)
		(layer "In6.Cu")
		(net "M_C_CPU0_SB_DQ<4>")
	)
	(segment
		(start 283.187394 -227.065078)
		(end 283.004514 -227.247958)
		(width 0.18288)
		(layer "In6.Cu")
		(net "M_C_CPU0_SB_DQ<4>")
	)
	(arc
		(start 340.501478 -241.156744)
		(mid 340.31428 -241.106601)
		(end 340.127082 -241.156744)
		(width 0.088646)
		(layer "In6.Cu")
		(net "M_C_CPU0_SB_DQ<4>")
	)
	(arc
		(start 332.983078 -241.156744)
		(mid 332.892925 -241.119203)
		(end 332.796134 -241.106198)
		(width 0.088646)
		(layer "In6.Cu")
		(net "M_C_CPU0_SB_DQ<4>")
	)
	(arc
		(start 340.11235 -241.16538)
		(mid 339.835875 -241.2327)
		(end 339.561678 -241.156744)
		(width 0.088646)
		(layer "In6.Cu")
		(net "M_C_CPU0_SB_DQ<4>")
	)
	(arc
		(start 336.742278 -241.156744)
		(mid 336.55508 -241.106601)
		(end 336.367882 -241.156744)
		(width 0.088646)
		(layer "In6.Cu")
		(net "M_C_CPU0_SB_DQ<4>")
	)
	(arc
		(start 337.682078 -241.156744)
		(mid 337.49488 -241.106601)
		(end 337.307682 -241.156744)
		(width 0.088646)
		(layer "In6.Cu")
		(net "M_C_CPU0_SB_DQ<4>")
	)
	(arc
		(start 341.996522 -241.16284)
		(mid 341.71809 -241.232686)
		(end 341.441278 -241.156744)
		(width 0.088646)
		(layer "In6.Cu")
		(net "M_C_CPU0_SB_DQ<4>")
	)
	(arc
		(start 339.187282 -241.156744)
		(mid 338.90458 -241.23252)
		(end 338.621878 -241.156744)
		(width 0.088646)
		(layer "In6.Cu")
		(net "M_C_CPU0_SB_DQ<4>")
	)
	(arc
		(start 337.29295 -241.16538)
		(mid 337.016475 -241.2327)
		(end 336.742278 -241.156744)
		(width 0.088646)
		(layer "In6.Cu")
		(net "M_C_CPU0_SB_DQ<4>")
	)
	(arc
		(start 343.13368 -241.481102)
		(mid 342.897512 -241.312897)
		(end 342.61933 -241.231166)
		(width 0.088646)
		(layer "In6.Cu")
		(net "M_C_CPU0_SB_DQ<4>")
	)
	(arc
		(start 336.357468 -241.16284)
		(mid 336.07929 -241.232563)
		(end 335.802732 -241.156744)
		(width 0.088646)
		(layer "In6.Cu")
		(net "M_C_CPU0_SB_DQ<4>")
	)
	(arc
		(start 339.561678 -241.156744)
		(mid 339.37448 -241.106601)
		(end 339.187282 -241.156744)
		(width 0.088646)
		(layer "In6.Cu")
		(net "M_C_CPU0_SB_DQ<4>")
	)
	(arc
		(start 334.478122 -241.16284)
		(mid 334.19969 -241.232686)
		(end 333.922878 -241.156744)
		(width 0.088646)
		(layer "In6.Cu")
		(net "M_C_CPU0_SB_DQ<4>")
	)
	(arc
		(start 335.428336 -241.156744)
		(mid 335.145634 -241.23252)
		(end 334.862932 -241.156744)
		(width 0.088646)
		(layer "In6.Cu")
		(net "M_C_CPU0_SB_DQ<4>")
	)
	(arc
		(start 342.381332 -241.156744)
		(mid 342.194134 -241.106601)
		(end 342.006936 -241.156744)
		(width 0.088646)
		(layer "In6.Cu")
		(net "M_C_CPU0_SB_DQ<4>")
	)
	(arc
		(start 334.862932 -241.156744)
		(mid 334.675734 -241.106601)
		(end 334.488536 -241.156744)
		(width 0.088646)
		(layer "In6.Cu")
		(net "M_C_CPU0_SB_DQ<4>")
	)
	(arc
		(start 338.621878 -241.156744)
		(mid 338.43468 -241.106601)
		(end 338.247482 -241.156744)
		(width 0.088646)
		(layer "In6.Cu")
		(net "M_C_CPU0_SB_DQ<4>")
	)
	(arc
		(start 338.23275 -241.16538)
		(mid 337.956275 -241.2327)
		(end 337.682078 -241.156744)
		(width 0.088646)
		(layer "In6.Cu")
		(net "M_C_CPU0_SB_DQ<4>")
	)
	(arc
		(start 341.05215 -241.16538)
		(mid 340.775675 -241.2327)
		(end 340.501478 -241.156744)
		(width 0.088646)
		(layer "In6.Cu")
		(net "M_C_CPU0_SB_DQ<4>")
	)
	(arc
		(start 335.802732 -241.156744)
		(mid 335.615534 -241.106601)
		(end 335.428336 -241.156744)
		(width 0.088646)
		(layer "In6.Cu")
		(net "M_C_CPU0_SB_DQ<4>")
	)
	(arc
		(start 333.922878 -241.156744)
		(mid 333.73568 -241.106601)
		(end 333.548482 -241.156744)
		(width 0.088646)
		(layer "In6.Cu")
		(net "M_C_CPU0_SB_DQ<4>")
	)
	(arc
		(start 342.59647 -241.228372)
		(mid 342.485271 -241.20346)
		(end 342.381332 -241.156744)
		(width 0.088646)
		(layer "In6.Cu")
		(net "M_C_CPU0_SB_DQ<4>")
	)
	(arc
		(start 341.441278 -241.156744)
		(mid 341.25408 -241.106601)
		(end 341.066882 -241.156744)
		(width 0.088646)
		(layer "In6.Cu")
		(net "M_C_CPU0_SB_DQ<4>")
	)
	(arc
		(start 333.53375 -241.16538)
		(mid 333.257275 -241.2327)
		(end 332.983078 -241.156744)
		(width 0.088646)
		(layer "In6.Cu")
		(net "M_C_CPU0_SB_DQ<4>")
	)
	(segment
		(start 277.601934 -230.041704)
		(end 277.58771 -230.055928)
		(width 0.101854)
		(layer "F.Cu")
		(net "M_C_CPU0_SB_DQ<3>")
	)
	(segment
		(start 280.606246 -229.740968)
		(end 280.606246 -229.892606)
		(width 0.20066)
		(layer "F.Cu")
		(net "M_C_CPU0_SB_DQ<3>")
	)
	(segment
		(start 283.916882 -229.616762)
		(end 282.811982 -229.616762)
		(width 0.20066)
		(layer "F.Cu")
		(net "M_C_CPU0_SB_DQ<3>")
	)
	(segment
		(start 281.788362 -229.82428)
		(end 281.34183 -229.82428)
		(width 0.20066)
		(layer "F.Cu")
		(net "M_C_CPU0_SB_DQ<3>")
	)
	(segment
		(start 277.839932 -230.041704)
		(end 277.601934 -230.041704)
		(width 0.101854)
		(layer "F.Cu")
		(net "M_C_CPU0_SB_DQ<3>")
	)
	(segment
		(start 280.73477 -229.612444)
		(end 280.606246 -229.740968)
		(width 0.20066)
		(layer "F.Cu")
		(net "M_C_CPU0_SB_DQ<3>")
	)
	(segment
		(start 281.34183 -229.82428)
		(end 281.129994 -229.612444)
		(width 0.20066)
		(layer "F.Cu")
		(net "M_C_CPU0_SB_DQ<3>")
	)
	(segment
		(start 276.96541 -229.616762)
		(end 275.268182 -229.616762)
		(width 0.20066)
		(layer "F.Cu")
		(net "M_C_CPU0_SB_DQ<3>")
	)
	(segment
		(start 282.811982 -229.616762)
		(end 281.99588 -229.616762)
		(width 0.20066)
		(layer "F.Cu")
		(net "M_C_CPU0_SB_DQ<3>")
	)
	(segment
		(start 279.912826 -230.041704)
		(end 277.839932 -230.041704)
		(width 0.1016)
		(layer "F.Cu")
		(net "M_C_CPU0_SB_DQ<3>")
	)
	(segment
		(start 277.58771 -230.055928)
		(end 277.233888 -230.055928)
		(width 0.20066)
		(layer "F.Cu")
		(net "M_C_CPU0_SB_DQ<3>")
	)
	(segment
		(start 281.99588 -229.616762)
		(end 281.788362 -229.82428)
		(width 0.20066)
		(layer "F.Cu")
		(net "M_C_CPU0_SB_DQ<3>")
	)
	(segment
		(start 277.091394 -229.913434)
		(end 277.091394 -229.742746)
		(width 0.20066)
		(layer "F.Cu")
		(net "M_C_CPU0_SB_DQ<3>")
	)
	(segment
		(start 280.457148 -230.041704)
		(end 279.912826 -230.041704)
		(width 0.20066)
		(layer "F.Cu")
		(net "M_C_CPU0_SB_DQ<3>")
	)
	(segment
		(start 345.01328 -243.644674)
		(end 345.01328 -243.108988)
		(width 0.20066)
		(layer "F.Cu")
		(net "M_C_CPU0_SB_DQ<3>")
	)
	(segment
		(start 277.233888 -230.055928)
		(end 277.091394 -229.913434)
		(width 0.20066)
		(layer "F.Cu")
		(net "M_C_CPU0_SB_DQ<3>")
	)
	(segment
		(start 345.013534 -243.644928)
		(end 345.01328 -243.644674)
		(width 0.20066)
		(layer "F.Cu")
		(net "M_C_CPU0_SB_DQ<3>")
	)
	(segment
		(start 281.129994 -229.612444)
		(end 280.73477 -229.612444)
		(width 0.20066)
		(layer "F.Cu")
		(net "M_C_CPU0_SB_DQ<3>")
	)
	(segment
		(start 280.606246 -229.892606)
		(end 280.457148 -230.041704)
		(width 0.20066)
		(layer "F.Cu")
		(net "M_C_CPU0_SB_DQ<3>")
	)
	(segment
		(start 277.091394 -229.742746)
		(end 276.96541 -229.616762)
		(width 0.20066)
		(layer "F.Cu")
		(net "M_C_CPU0_SB_DQ<3>")
	)
	(segment
		(start 293.19728 -234.291632)
		(end 292.5064 -234.291632)
		(width 0.18288)
		(layer "In6.Cu")
		(net "M_C_CPU0_SB_DQ<3>")
	)
	(segment
		(start 308.535832 -236.521498)
		(end 308.535832 -236.676946)
		(width 0.18288)
		(layer "In6.Cu")
		(net "M_C_CPU0_SB_DQ<3>")
	)
	(segment
		(start 301.500794 -235.14177)
		(end 301.317914 -234.95889)
		(width 0.18288)
		(layer "In6.Cu")
		(net "M_C_CPU0_SB_DQ<3>")
	)
	(segment
		(start 342.845644 -242.861846)
		(end 342.745568 -242.961922)
		(width 0.088646)
		(layer "In6.Cu")
		(net "M_C_CPU0_SB_DQ<3>")
	)
	(segment
		(start 314.750704 -237.664752)
		(end 313.10072 -237.664752)
		(width 0.18288)
		(layer "In6.Cu")
		(net "M_C_CPU0_SB_DQ<3>")
	)
	(segment
		(start 308.718712 -236.338618)
		(end 308.535832 -236.521498)
		(width 0.18288)
		(layer "In6.Cu")
		(net "M_C_CPU0_SB_DQ<3>")
	)
	(segment
		(start 293.38016 -233.917998)
		(end 293.38016 -234.108752)
		(width 0.18288)
		(layer "In6.Cu")
		(net "M_C_CPU0_SB_DQ<3>")
	)
	(segment
		(start 305.430682 -235.850684)
		(end 305.430682 -235.472478)
		(width 0.18288)
		(layer "In6.Cu")
		(net "M_C_CPU0_SB_DQ<3>")
	)
	(segment
		(start 342.57996 -243.183664)
		(end 342.523064 -243.288058)
		(width 0.088646)
		(layer "In6.Cu")
		(net "M_C_CPU0_SB_DQ<3>")
	)
	(segment
		(start 336.367882 -243.433346)
		(end 336.357468 -243.42725)
		(width 0.088646)
		(layer "In6.Cu")
		(net "M_C_CPU0_SB_DQ<3>")
	)
	(segment
		(start 303.855374 -236.033564)
		(end 302.96358 -235.14177)
		(width 0.18288)
		(layer "In6.Cu")
		(net "M_C_CPU0_SB_DQ<3>")
	)
	(segment
		(start 306.7431 -236.033564)
		(end 305.613562 -236.033564)
		(width 0.18288)
		(layer "In6.Cu")
		(net "M_C_CPU0_SB_DQ<3>")
	)
	(segment
		(start 334.877664 -243.42471)
		(end 334.862932 -243.433346)
		(width 0.088646)
		(layer "In6.Cu")
		(net "M_C_CPU0_SB_DQ<3>")
	)
	(segment
		(start 291.20973 -232.994962)
		(end 289.932364 -231.717596)
		(width 0.18288)
		(layer "In6.Cu")
		(net "M_C_CPU0_SB_DQ<3>")
	)
	(segment
		(start 288.51733 -231.717596)
		(end 287.660334 -230.8606)
		(width 0.18288)
		(layer "In6.Cu")
		(net "M_C_CPU0_SB_DQ<3>")
	)
	(segment
		(start 301.317914 -234.95889)
		(end 301.317914 -234.702604)
		(width 0.18288)
		(layer "In6.Cu")
		(net "M_C_CPU0_SB_DQ<3>")
	)
	(segment
		(start 292.5064 -234.291632)
		(end 291.956998 -233.74223)
		(width 0.18288)
		(layer "In6.Cu")
		(net "M_C_CPU0_SB_DQ<3>")
	)
	(segment
		(start 300.627034 -234.702604)
		(end 300.627034 -234.95889)
		(width 0.18288)
		(layer "In6.Cu")
		(net "M_C_CPU0_SB_DQ<3>")
	)
	(segment
		(start 289.932364 -231.717596)
		(end 288.51733 -231.717596)
		(width 0.18288)
		(layer "In6.Cu")
		(net "M_C_CPU0_SB_DQ<3>")
	)
	(segment
		(start 285.447994 -230.07828)
		(end 284.3784 -230.07828)
		(width 0.18288)
		(layer "In6.Cu")
		(net "M_C_CPU0_SB_DQ<3>")
	)
	(segment
		(start 305.247802 -235.289598)
		(end 304.922682 -235.289598)
		(width 0.18288)
		(layer "In6.Cu")
		(net "M_C_CPU0_SB_DQ<3>")
	)
	(segment
		(start 331.973682 -243.42471)
		(end 331.323442 -242.77447)
		(width 0.088646)
		(layer "In6.Cu")
		(net "M_C_CPU0_SB_DQ<3>")
	)
	(segment
		(start 342.386412 -243.430552)
		(end 342.37549 -243.436648)
		(width 0.088646)
		(layer "In6.Cu")
		(net "M_C_CPU0_SB_DQ<3>")
	)
	(segment
		(start 313.10072 -237.664752)
		(end 312.295794 -236.859826)
		(width 0.18288)
		(layer "In6.Cu")
		(net "M_C_CPU0_SB_DQ<3>")
	)
	(segment
		(start 337.688174 -243.430044)
		(end 337.67649 -243.436648)
		(width 0.088646)
		(layer "In6.Cu")
		(net "M_C_CPU0_SB_DQ<3>")
	)
	(segment
		(start 330.85405 -242.77447)
		(end 330.014072 -241.934492)
		(width 0.18288)
		(layer "In6.Cu")
		(net "M_C_CPU0_SB_DQ<3>")
	)
	(segment
		(start 291.901118 -232.820718)
		(end 291.642546 -232.820718)
		(width 0.18288)
		(layer "In6.Cu")
		(net "M_C_CPU0_SB_DQ<3>")
	)
	(segment
		(start 297.953938 -235.14177)
		(end 297.1038 -234.291632)
		(width 0.18288)
		(layer "In6.Cu")
		(net "M_C_CPU0_SB_DQ<3>")
	)
	(segment
		(start 304.922682 -235.289598)
		(end 304.739802 -235.472478)
		(width 0.18288)
		(layer "In6.Cu")
		(net "M_C_CPU0_SB_DQ<3>")
	)
	(segment
		(start 331.029564 -242.77447)
		(end 330.85405 -242.77447)
		(width 0.18288)
		(layer "In6.Cu")
		(net "M_C_CPU0_SB_DQ<3>")
	)
	(segment
		(start 301.135034 -234.519724)
		(end 300.809914 -234.519724)
		(width 0.18288)
		(layer "In6.Cu")
		(net "M_C_CPU0_SB_DQ<3>")
	)
	(segment
		(start 304.739802 -235.472478)
		(end 304.739802 -235.850684)
		(width 0.18288)
		(layer "In6.Cu")
		(net "M_C_CPU0_SB_DQ<3>")
	)
	(segment
		(start 307.569362 -236.859826)
		(end 306.7431 -236.033564)
		(width 0.18288)
		(layer "In6.Cu")
		(net "M_C_CPU0_SB_DQ<3>")
	)
	(segment
		(start 309.043832 -236.338618)
		(end 308.718712 -236.338618)
		(width 0.18288)
		(layer "In6.Cu")
		(net "M_C_CPU0_SB_DQ<3>")
	)
	(segment
		(start 339.567774 -243.430044)
		(end 339.55609 -243.436648)
		(width 0.088646)
		(layer "In6.Cu")
		(net "M_C_CPU0_SB_DQ<3>")
	)
	(segment
		(start 309.226712 -236.521498)
		(end 309.043832 -236.338618)
		(width 0.18288)
		(layer "In6.Cu")
		(net "M_C_CPU0_SB_DQ<3>")
	)
	(segment
		(start 291.642546 -232.820718)
		(end 291.468302 -232.994962)
		(width 0.18288)
		(layer "In6.Cu")
		(net "M_C_CPU0_SB_DQ<3>")
	)
	(segment
		(start 301.317914 -234.702604)
		(end 301.135034 -234.519724)
		(width 0.18288)
		(layer "In6.Cu")
		(net "M_C_CPU0_SB_DQ<3>")
	)
	(segment
		(start 336.748374 -243.430044)
		(end 336.742532 -243.433346)
		(width 0.088646)
		(layer "In6.Cu")
		(net "M_C_CPU0_SB_DQ<3>")
	)
	(segment
		(start 294.07104 -233.917998)
		(end 293.88816 -233.735118)
		(width 0.18288)
		(layer "In6.Cu")
		(net "M_C_CPU0_SB_DQ<3>")
	)
	(segment
		(start 305.430682 -235.472478)
		(end 305.247802 -235.289598)
		(width 0.18288)
		(layer "In6.Cu")
		(net "M_C_CPU0_SB_DQ<3>")
	)
	(segment
		(start 332.998064 -243.42471)
		(end 332.983332 -243.433346)
		(width 0.088646)
		(layer "In6.Cu")
		(net "M_C_CPU0_SB_DQ<3>")
	)
	(segment
		(start 300.809914 -234.519724)
		(end 300.627034 -234.702604)
		(width 0.18288)
		(layer "In6.Cu")
		(net "M_C_CPU0_SB_DQ<3>")
	)
	(segment
		(start 343.326974 -242.787932)
		(end 343.321132 -242.784376)
		(width 0.088646)
		(layer "In6.Cu")
		(net "M_C_CPU0_SB_DQ<3>")
	)
	(segment
		(start 286.230314 -230.8606)
		(end 285.447994 -230.07828)
		(width 0.18288)
		(layer "In6.Cu")
		(net "M_C_CPU0_SB_DQ<3>")
	)
	(segment
		(start 292.131242 -233.050842)
		(end 291.901118 -232.820718)
		(width 0.18288)
		(layer "In6.Cu")
		(net "M_C_CPU0_SB_DQ<3>")
	)
	(segment
		(start 291.956998 -233.74223)
		(end 291.956998 -233.483658)
		(width 0.18288)
		(layer "In6.Cu")
		(net "M_C_CPU0_SB_DQ<3>")
	)
	(segment
		(start 304.556922 -236.033564)
		(end 303.855374 -236.033564)
		(width 0.18288)
		(layer "In6.Cu")
		(net "M_C_CPU0_SB_DQ<3>")
	)
	(segment
		(start 284.3784 -230.07828)
		(end 283.916882 -229.616762)
		(width 0.18288)
		(layer "In6.Cu")
		(net "M_C_CPU0_SB_DQ<3>")
	)
	(segment
		(start 341.447374 -243.430044)
		(end 341.43569 -243.436648)
		(width 0.088646)
		(layer "In6.Cu")
		(net "M_C_CPU0_SB_DQ<3>")
	)
	(segment
		(start 331.323442 -242.77447)
		(end 331.029564 -242.77447)
		(width 0.088646)
		(layer "In6.Cu")
		(net "M_C_CPU0_SB_DQ<3>")
	)
	(segment
		(start 300.627034 -234.95889)
		(end 300.444154 -235.14177)
		(width 0.18288)
		(layer "In6.Cu")
		(net "M_C_CPU0_SB_DQ<3>")
	)
	(segment
		(start 287.660334 -230.8606)
		(end 286.230314 -230.8606)
		(width 0.18288)
		(layer "In6.Cu")
		(net "M_C_CPU0_SB_DQ<3>")
	)
	(segment
		(start 308.535832 -236.676946)
		(end 308.352952 -236.859826)
		(width 0.18288)
		(layer "In6.Cu")
		(net "M_C_CPU0_SB_DQ<3>")
	)
	(segment
		(start 293.56304 -233.735118)
		(end 293.38016 -233.917998)
		(width 0.18288)
		(layer "In6.Cu")
		(net "M_C_CPU0_SB_DQ<3>")
	)
	(segment
		(start 309.226712 -236.676946)
		(end 309.226712 -236.521498)
		(width 0.18288)
		(layer "In6.Cu")
		(net "M_C_CPU0_SB_DQ<3>")
	)
	(segment
		(start 340.507574 -243.430044)
		(end 340.49589 -243.436648)
		(width 0.088646)
		(layer "In6.Cu")
		(net "M_C_CPU0_SB_DQ<3>")
	)
	(segment
		(start 319.020444 -241.934492)
		(end 314.750704 -237.664752)
		(width 0.18288)
		(layer "In6.Cu")
		(net "M_C_CPU0_SB_DQ<3>")
	)
	(segment
		(start 338.627974 -243.430044)
		(end 338.61629 -243.436648)
		(width 0.088646)
		(layer "In6.Cu")
		(net "M_C_CPU0_SB_DQ<3>")
	)
	(segment
		(start 336.742532 -243.433346)
		(end 336.738722 -243.435632)
		(width 0.088646)
		(layer "In6.Cu")
		(net "M_C_CPU0_SB_DQ<3>")
	)
	(segment
		(start 330.014072 -241.934492)
		(end 319.020444 -241.934492)
		(width 0.18288)
		(layer "In6.Cu")
		(net "M_C_CPU0_SB_DQ<3>")
	)
	(segment
		(start 291.468302 -232.994962)
		(end 291.20973 -232.994962)
		(width 0.18288)
		(layer "In6.Cu")
		(net "M_C_CPU0_SB_DQ<3>")
	)
	(segment
		(start 312.295794 -236.859826)
		(end 309.409592 -236.859826)
		(width 0.18288)
		(layer "In6.Cu")
		(net "M_C_CPU0_SB_DQ<3>")
	)
	(segment
		(start 332.058264 -243.42471)
		(end 331.973682 -243.42471)
		(width 0.088646)
		(layer "In6.Cu")
		(net "M_C_CPU0_SB_DQ<3>")
	)
	(segment
		(start 344.658696 -243.013992)
		(end 344.25509 -242.781074)
		(width 0.088646)
		(layer "In6.Cu")
		(net "M_C_CPU0_SB_DQ<3>")
	)
	(segment
		(start 343.321132 -242.784376)
		(end 343.31529 -242.781074)
		(width 0.088646)
		(layer "In6.Cu")
		(net "M_C_CPU0_SB_DQ<3>")
	)
	(segment
		(start 300.444154 -235.14177)
		(end 297.953938 -235.14177)
		(width 0.18288)
		(layer "In6.Cu")
		(net "M_C_CPU0_SB_DQ<3>")
	)
	(segment
		(start 292.131242 -233.309414)
		(end 292.131242 -233.050842)
		(width 0.18288)
		(layer "In6.Cu")
		(net "M_C_CPU0_SB_DQ<3>")
	)
	(segment
		(start 308.352952 -236.859826)
		(end 307.569362 -236.859826)
		(width 0.18288)
		(layer "In6.Cu")
		(net "M_C_CPU0_SB_DQ<3>")
	)
	(segment
		(start 304.739802 -235.850684)
		(end 304.556922 -236.033564)
		(width 0.18288)
		(layer "In6.Cu")
		(net "M_C_CPU0_SB_DQ<3>")
	)
	(segment
		(start 297.1038 -234.291632)
		(end 294.25392 -234.291632)
		(width 0.18288)
		(layer "In6.Cu")
		(net "M_C_CPU0_SB_DQ<3>")
	)
	(segment
		(start 293.88816 -233.735118)
		(end 293.56304 -233.735118)
		(width 0.18288)
		(layer "In6.Cu")
		(net "M_C_CPU0_SB_DQ<3>")
	)
	(segment
		(start 309.409592 -236.859826)
		(end 309.226712 -236.676946)
		(width 0.18288)
		(layer "In6.Cu")
		(net "M_C_CPU0_SB_DQ<3>")
	)
	(segment
		(start 305.613562 -236.033564)
		(end 305.430682 -235.850684)
		(width 0.18288)
		(layer "In6.Cu")
		(net "M_C_CPU0_SB_DQ<3>")
	)
	(segment
		(start 333.937864 -243.42471)
		(end 333.923132 -243.433346)
		(width 0.088646)
		(layer "In6.Cu")
		(net "M_C_CPU0_SB_DQ<3>")
	)
	(segment
		(start 294.07104 -234.108752)
		(end 294.07104 -233.917998)
		(width 0.18288)
		(layer "In6.Cu")
		(net "M_C_CPU0_SB_DQ<3>")
	)
	(segment
		(start 294.25392 -234.291632)
		(end 294.07104 -234.108752)
		(width 0.18288)
		(layer "In6.Cu")
		(net "M_C_CPU0_SB_DQ<3>")
	)
	(segment
		(start 291.956998 -233.483658)
		(end 292.131242 -233.309414)
		(width 0.18288)
		(layer "In6.Cu")
		(net "M_C_CPU0_SB_DQ<3>")
	)
	(segment
		(start 293.38016 -234.108752)
		(end 293.19728 -234.291632)
		(width 0.18288)
		(layer "In6.Cu")
		(net "M_C_CPU0_SB_DQ<3>")
	)
	(segment
		(start 302.96358 -235.14177)
		(end 301.500794 -235.14177)
		(width 0.18288)
		(layer "In6.Cu")
		(net "M_C_CPU0_SB_DQ<3>")
	)
	(arc
		(start 337.67649 -243.436648)
		(mid 337.491635 -243.483598)
		(end 337.307682 -243.433346)
		(width 0.088646)
		(layer "In6.Cu")
		(net "M_C_CPU0_SB_DQ<3>")
	)
	(arc
		(start 339.55609 -243.436648)
		(mid 339.371235 -243.483598)
		(end 339.187282 -243.433346)
		(width 0.088646)
		(layer "In6.Cu")
		(net "M_C_CPU0_SB_DQ<3>")
	)
	(arc
		(start 341.066882 -243.433346)
		(mid 340.787679 -243.357706)
		(end 340.507574 -243.430044)
		(width 0.088646)
		(layer "In6.Cu")
		(net "M_C_CPU0_SB_DQ<3>")
	)
	(arc
		(start 334.862932 -243.433346)
		(mid 334.675734 -243.483489)
		(end 334.488536 -243.433346)
		(width 0.088646)
		(layer "In6.Cu")
		(net "M_C_CPU0_SB_DQ<3>")
	)
	(arc
		(start 341.43569 -243.436648)
		(mid 341.250835 -243.483598)
		(end 341.066882 -243.433346)
		(width 0.088646)
		(layer "In6.Cu")
		(net "M_C_CPU0_SB_DQ<3>")
	)
	(arc
		(start 342.37549 -243.436648)
		(mid 342.190635 -243.483598)
		(end 342.006682 -243.433346)
		(width 0.088646)
		(layer "In6.Cu")
		(net "M_C_CPU0_SB_DQ<3>")
	)
	(arc
		(start 336.738722 -243.435632)
		(mid 336.553003 -243.483584)
		(end 336.367882 -243.433346)
		(width 0.088646)
		(layer "In6.Cu")
		(net "M_C_CPU0_SB_DQ<3>")
	)
	(arc
		(start 338.61629 -243.436648)
		(mid 338.431435 -243.483598)
		(end 338.247482 -243.433346)
		(width 0.088646)
		(layer "In6.Cu")
		(net "M_C_CPU0_SB_DQ<3>")
	)
	(arc
		(start 335.428336 -243.433346)
		(mid 335.154137 -243.357511)
		(end 334.877664 -243.42471)
		(width 0.088646)
		(layer "In6.Cu")
		(net "M_C_CPU0_SB_DQ<3>")
	)
	(arc
		(start 333.923132 -243.433346)
		(mid 333.735934 -243.483489)
		(end 333.548736 -243.433346)
		(width 0.088646)
		(layer "In6.Cu")
		(net "M_C_CPU0_SB_DQ<3>")
	)
	(arc
		(start 339.187282 -243.433346)
		(mid 338.908079 -243.357706)
		(end 338.627974 -243.430044)
		(width 0.088646)
		(layer "In6.Cu")
		(net "M_C_CPU0_SB_DQ<3>")
	)
	(arc
		(start 342.006682 -243.433346)
		(mid 341.727479 -243.357706)
		(end 341.447374 -243.430044)
		(width 0.088646)
		(layer "In6.Cu")
		(net "M_C_CPU0_SB_DQ<3>")
	)
	(arc
		(start 337.307682 -243.433346)
		(mid 337.028479 -243.357706)
		(end 336.748374 -243.430044)
		(width 0.088646)
		(layer "In6.Cu")
		(net "M_C_CPU0_SB_DQ<3>")
	)
	(arc
		(start 336.357468 -243.42725)
		(mid 336.07929 -243.357527)
		(end 335.802732 -243.433346)
		(width 0.088646)
		(layer "In6.Cu")
		(net "M_C_CPU0_SB_DQ<3>")
	)
	(arc
		(start 342.523064 -243.288058)
		(mid 342.464306 -243.368485)
		(end 342.386412 -243.430552)
		(width 0.088646)
		(layer "In6.Cu")
		(net "M_C_CPU0_SB_DQ<3>")
	)
	(arc
		(start 343.886282 -242.784376)
		(mid 343.607108 -242.860141)
		(end 343.326974 -242.787932)
		(width 0.088646)
		(layer "In6.Cu")
		(net "M_C_CPU0_SB_DQ<3>")
	)
	(arc
		(start 335.802732 -243.433346)
		(mid 335.615534 -243.483489)
		(end 335.428336 -243.433346)
		(width 0.088646)
		(layer "In6.Cu")
		(net "M_C_CPU0_SB_DQ<3>")
	)
	(arc
		(start 333.548736 -243.433346)
		(mid 333.274537 -243.357511)
		(end 332.998064 -243.42471)
		(width 0.088646)
		(layer "In6.Cu")
		(net "M_C_CPU0_SB_DQ<3>")
	)
	(arc
		(start 340.127082 -243.433346)
		(mid 339.847879 -243.357706)
		(end 339.567774 -243.430044)
		(width 0.088646)
		(layer "In6.Cu")
		(net "M_C_CPU0_SB_DQ<3>")
	)
	(arc
		(start 332.983332 -243.433346)
		(mid 332.796134 -243.483489)
		(end 332.608936 -243.433346)
		(width 0.088646)
		(layer "In6.Cu")
		(net "M_C_CPU0_SB_DQ<3>")
	)
	(arc
		(start 345.01328 -243.108988)
		(mid 344.829737 -243.084825)
		(end 344.658696 -243.013992)
		(width 0.088646)
		(layer "In6.Cu")
		(net "M_C_CPU0_SB_DQ<3>")
	)
	(arc
		(start 334.488536 -243.433346)
		(mid 334.214337 -243.357511)
		(end 333.937864 -243.42471)
		(width 0.088646)
		(layer "In6.Cu")
		(net "M_C_CPU0_SB_DQ<3>")
	)
	(arc
		(start 332.608936 -243.433346)
		(mid 332.334737 -243.357511)
		(end 332.058264 -243.42471)
		(width 0.088646)
		(layer "In6.Cu")
		(net "M_C_CPU0_SB_DQ<3>")
	)
	(arc
		(start 342.946482 -242.784376)
		(mid 342.893518 -242.819799)
		(end 342.845644 -242.861846)
		(width 0.088646)
		(layer "In6.Cu")
		(net "M_C_CPU0_SB_DQ<3>")
	)
	(arc
		(start 338.247482 -243.433346)
		(mid 337.968279 -243.357706)
		(end 337.688174 -243.430044)
		(width 0.088646)
		(layer "In6.Cu")
		(net "M_C_CPU0_SB_DQ<3>")
	)
	(arc
		(start 340.49589 -243.436648)
		(mid 340.311035 -243.483598)
		(end 340.127082 -243.433346)
		(width 0.088646)
		(layer "In6.Cu")
		(net "M_C_CPU0_SB_DQ<3>")
	)
	(arc
		(start 342.745568 -242.961922)
		(mid 342.654796 -243.066841)
		(end 342.57996 -243.183664)
		(width 0.088646)
		(layer "In6.Cu")
		(net "M_C_CPU0_SB_DQ<3>")
	)
	(arc
		(start 344.25509 -242.781074)
		(mid 344.070235 -242.734156)
		(end 343.886282 -242.784376)
		(width 0.088646)
		(layer "In6.Cu")
		(net "M_C_CPU0_SB_DQ<3>")
	)
	(arc
		(start 343.31529 -242.781074)
		(mid 343.130435 -242.734156)
		(end 342.946482 -242.784376)
		(width 0.088646)
		(layer "In6.Cu")
		(net "M_C_CPU0_SB_DQ<3>")
	)
	(segment
		(start 277.58771 -196.055742)
		(end 277.233888 -196.055742)
		(width 0.20066)
		(layer "F.Cu")
		(net "M_C_CPU0_SB_DQ<31>")
	)
	(segment
		(start 280.457148 -196.041518)
		(end 279.912826 -196.041518)
		(width 0.20066)
		(layer "F.Cu")
		(net "M_C_CPU0_SB_DQ<31>")
	)
	(segment
		(start 277.091394 -195.74256)
		(end 276.96541 -195.616576)
		(width 0.20066)
		(layer "F.Cu")
		(net "M_C_CPU0_SB_DQ<31>")
	)
	(segment
		(start 280.606246 -195.89242)
		(end 280.457148 -196.041518)
		(width 0.20066)
		(layer "F.Cu")
		(net "M_C_CPU0_SB_DQ<31>")
	)
	(segment
		(start 279.912826 -196.041518)
		(end 277.839932 -196.041518)
		(width 0.1016)
		(layer "F.Cu")
		(net "M_C_CPU0_SB_DQ<31>")
	)
	(segment
		(start 345.95308 -227.36683)
		(end 345.95308 -226.831144)
		(width 0.20066)
		(layer "F.Cu")
		(net "M_C_CPU0_SB_DQ<31>")
	)
	(segment
		(start 283.916882 -195.616576)
		(end 282.811982 -195.616576)
		(width 0.20066)
		(layer "F.Cu")
		(net "M_C_CPU0_SB_DQ<31>")
	)
	(segment
		(start 280.606246 -195.740782)
		(end 280.606246 -195.89242)
		(width 0.20066)
		(layer "F.Cu")
		(net "M_C_CPU0_SB_DQ<31>")
	)
	(segment
		(start 345.953334 -227.367084)
		(end 345.95308 -227.36683)
		(width 0.20066)
		(layer "F.Cu")
		(net "M_C_CPU0_SB_DQ<31>")
	)
	(segment
		(start 281.34183 -195.824094)
		(end 281.129994 -195.612258)
		(width 0.20066)
		(layer "F.Cu")
		(net "M_C_CPU0_SB_DQ<31>")
	)
	(segment
		(start 282.811982 -195.616576)
		(end 281.99588 -195.616576)
		(width 0.20066)
		(layer "F.Cu")
		(net "M_C_CPU0_SB_DQ<31>")
	)
	(segment
		(start 277.233888 -196.055742)
		(end 277.091394 -195.913248)
		(width 0.20066)
		(layer "F.Cu")
		(net "M_C_CPU0_SB_DQ<31>")
	)
	(segment
		(start 277.839932 -196.041518)
		(end 277.601934 -196.041518)
		(width 0.101854)
		(layer "F.Cu")
		(net "M_C_CPU0_SB_DQ<31>")
	)
	(segment
		(start 281.129994 -195.612258)
		(end 280.73477 -195.612258)
		(width 0.20066)
		(layer "F.Cu")
		(net "M_C_CPU0_SB_DQ<31>")
	)
	(segment
		(start 277.091394 -195.913248)
		(end 277.091394 -195.74256)
		(width 0.20066)
		(layer "F.Cu")
		(net "M_C_CPU0_SB_DQ<31>")
	)
	(segment
		(start 276.96541 -195.616576)
		(end 275.268182 -195.616576)
		(width 0.20066)
		(layer "F.Cu")
		(net "M_C_CPU0_SB_DQ<31>")
	)
	(segment
		(start 277.601934 -196.041518)
		(end 277.58771 -196.055742)
		(width 0.101854)
		(layer "F.Cu")
		(net "M_C_CPU0_SB_DQ<31>")
	)
	(segment
		(start 281.788362 -195.824094)
		(end 281.34183 -195.824094)
		(width 0.20066)
		(layer "F.Cu")
		(net "M_C_CPU0_SB_DQ<31>")
	)
	(segment
		(start 280.73477 -195.612258)
		(end 280.606246 -195.740782)
		(width 0.20066)
		(layer "F.Cu")
		(net "M_C_CPU0_SB_DQ<31>")
	)
	(segment
		(start 281.99588 -195.616576)
		(end 281.788362 -195.824094)
		(width 0.20066)
		(layer "F.Cu")
		(net "M_C_CPU0_SB_DQ<31>")
	)
	(segment
		(start 330.510896 -219.575126)
		(end 330.510896 -219.03055)
		(width 0.18288)
		(layer "In6.Cu")
		(net "M_C_CPU0_SB_DQ<31>")
	)
	(segment
		(start 288.291778 -193.725292)
		(end 287.510728 -193.725292)
		(width 0.18288)
		(layer "In6.Cu")
		(net "M_C_CPU0_SB_DQ<31>")
	)
	(segment
		(start 339.279484 -224.404936)
		(end 339.279484 -224.389442)
		(width 0.088646)
		(layer "In6.Cu")
		(net "M_C_CPU0_SB_DQ<31>")
	)
	(segment
		(start 303.669446 -194.146932)
		(end 303.681638 -194.010788)
		(width 0.18288)
		(layer "In6.Cu")
		(net "M_C_CPU0_SB_DQ<31>")
	)
	(segment
		(start 338.253578 -224.875344)
		(end 338.247482 -224.8789)
		(width 0.088646)
		(layer "In6.Cu")
		(net "M_C_CPU0_SB_DQ<31>")
	)
	(segment
		(start 288.474658 -194.175126)
		(end 288.474658 -193.908172)
		(width 0.18288)
		(layer "In6.Cu")
		(net "M_C_CPU0_SB_DQ<31>")
	)
	(segment
		(start 289.168078 -194.175126)
		(end 288.985198 -194.358006)
		(width 0.18288)
		(layer "In6.Cu")
		(net "M_C_CPU0_SB_DQ<31>")
	)
	(segment
		(start 343.886536 -226.506786)
		(end 343.876122 -226.512882)
		(width 0.088646)
		(layer "In6.Cu")
		(net "M_C_CPU0_SB_DQ<31>")
	)
	(segment
		(start 308.587394 -194.898772)
		(end 308.168548 -194.479926)
		(width 0.18288)
		(layer "In6.Cu")
		(net "M_C_CPU0_SB_DQ<31>")
	)
	(segment
		(start 289.168078 -193.908172)
		(end 289.168078 -194.175126)
		(width 0.18288)
		(layer "In6.Cu")
		(net "M_C_CPU0_SB_DQ<31>")
	)
	(segment
		(start 307.606192 -194.237864)
		(end 306.813458 -194.105784)
		(width 0.18288)
		(layer "In6.Cu")
		(net "M_C_CPU0_SB_DQ<31>")
	)
	(segment
		(start 291.734748 -194.301364)
		(end 291.409628 -194.301364)
		(width 0.18288)
		(layer "In6.Cu")
		(net "M_C_CPU0_SB_DQ<31>")
	)
	(segment
		(start 344.671142 -227.038662)
		(end 344.504772 -226.750372)
		(width 0.088646)
		(layer "In6.Cu")
		(net "M_C_CPU0_SB_DQ<31>")
	)
	(segment
		(start 332.998064 -223.259904)
		(end 332.983332 -223.251268)
		(width 0.088646)
		(layer "In6.Cu")
		(net "M_C_CPU0_SB_DQ<31>")
	)
	(segment
		(start 308.587394 -195.686426)
		(end 308.587394 -194.898772)
		(width 0.18288)
		(layer "In6.Cu")
		(net "M_C_CPU0_SB_DQ<31>")
	)
	(segment
		(start 284.898084 -194.331336)
		(end 284.673294 -194.556126)
		(width 0.18288)
		(layer "In6.Cu")
		(net "M_C_CPU0_SB_DQ<31>")
	)
	(segment
		(start 292.100508 -193.725292)
		(end 291.917628 -193.908172)
		(width 0.18288)
		(layer "In6.Cu")
		(net "M_C_CPU0_SB_DQ<31>")
	)
	(segment
		(start 330.510896 -219.03055)
		(end 321.712336 -210.23199)
		(width 0.18288)
		(layer "In6.Cu")
		(net "M_C_CPU0_SB_DQ<31>")
	)
	(segment
		(start 288.657538 -194.358006)
		(end 288.474658 -194.175126)
		(width 0.18288)
		(layer "In6.Cu")
		(net "M_C_CPU0_SB_DQ<31>")
	)
	(segment
		(start 331.008228 -220.072458)
		(end 330.510896 -219.575126)
		(width 0.18288)
		(layer "In6.Cu")
		(net "M_C_CPU0_SB_DQ<31>")
	)
	(segment
		(start 340.133178 -224.875344)
		(end 340.127082 -224.8789)
		(width 0.088646)
		(layer "In6.Cu")
		(net "M_C_CPU0_SB_DQ<31>")
	)
	(segment
		(start 311.407048 -197.718426)
		(end 310.518048 -196.829426)
		(width 0.18288)
		(layer "In6.Cu")
		(net "M_C_CPU0_SB_DQ<31>")
	)
	(segment
		(start 313.797188 -199.247252)
		(end 312.268362 -197.718426)
		(width 0.18288)
		(layer "In6.Cu")
		(net "M_C_CPU0_SB_DQ<31>")
	)
	(segment
		(start 345.59748 -226.926394)
		(end 345.200478 -227.155502)
		(width 0.088646)
		(layer "In6.Cu")
		(net "M_C_CPU0_SB_DQ<31>")
	)
	(segment
		(start 337.221322 -224.070164)
		(end 337.212432 -224.065084)
		(width 0.088646)
		(layer "In6.Cu")
		(net "M_C_CPU0_SB_DQ<31>")
	)
	(segment
		(start 336.368136 -223.251268)
		(end 336.353404 -223.259904)
		(width 0.088646)
		(layer "In6.Cu")
		(net "M_C_CPU0_SB_DQ<31>")
	)
	(segment
		(start 291.917628 -193.908172)
		(end 291.917628 -194.118484)
		(width 0.18288)
		(layer "In6.Cu")
		(net "M_C_CPU0_SB_DQ<31>")
	)
	(segment
		(start 341.450168 -224.88398)
		(end 341.441278 -224.8789)
		(width 0.088646)
		(layer "In6.Cu")
		(net "M_C_CPU0_SB_DQ<31>")
	)
	(segment
		(start 343.038684 -226.032822)
		(end 343.038684 -226.017328)
		(width 0.088646)
		(layer "In6.Cu")
		(net "M_C_CPU0_SB_DQ<31>")
	)
	(segment
		(start 289.350958 -193.725292)
		(end 289.168078 -193.908172)
		(width 0.18288)
		(layer "In6.Cu")
		(net "M_C_CPU0_SB_DQ<31>")
	)
	(segment
		(start 291.043868 -193.725292)
		(end 289.350958 -193.725292)
		(width 0.18288)
		(layer "In6.Cu")
		(net "M_C_CPU0_SB_DQ<31>")
	)
	(segment
		(start 332.70063 -221.76486)
		(end 331.008228 -220.072458)
		(width 0.088646)
		(layer "In6.Cu")
		(net "M_C_CPU0_SB_DQ<31>")
	)
	(segment
		(start 336.751168 -223.256348)
		(end 336.742278 -223.251268)
		(width 0.088646)
		(layer "In6.Cu")
		(net "M_C_CPU0_SB_DQ<31>")
	)
	(segment
		(start 291.917628 -194.118484)
		(end 291.734748 -194.301364)
		(width 0.18288)
		(layer "In6.Cu")
		(net "M_C_CPU0_SB_DQ<31>")
	)
	(segment
		(start 303.681638 -194.010788)
		(end 303.515522 -193.812668)
		(width 0.18288)
		(layer "In6.Cu")
		(net "M_C_CPU0_SB_DQ<31>")
	)
	(segment
		(start 288.985198 -194.358006)
		(end 288.657538 -194.358006)
		(width 0.18288)
		(layer "In6.Cu")
		(net "M_C_CPU0_SB_DQ<31>")
	)
	(segment
		(start 321.712336 -210.23199)
		(end 318.82334 -203.257912)
		(width 0.18288)
		(layer "In6.Cu")
		(net "M_C_CPU0_SB_DQ<31>")
	)
	(segment
		(start 304.570638 -193.90614)
		(end 304.372264 -194.072256)
		(width 0.18288)
		(layer "In6.Cu")
		(net "M_C_CPU0_SB_DQ<31>")
	)
	(segment
		(start 291.409628 -194.301364)
		(end 291.226748 -194.118484)
		(width 0.18288)
		(layer "In6.Cu")
		(net "M_C_CPU0_SB_DQ<31>")
	)
	(segment
		(start 302.535082 -193.725292)
		(end 292.100508 -193.725292)
		(width 0.18288)
		(layer "In6.Cu")
		(net "M_C_CPU0_SB_DQ<31>")
	)
	(segment
		(start 291.226748 -193.908172)
		(end 291.043868 -193.725292)
		(width 0.18288)
		(layer "In6.Cu")
		(net "M_C_CPU0_SB_DQ<31>")
	)
	(segment
		(start 340.127082 -224.8789)
		(end 340.11235 -224.887536)
		(width 0.088646)
		(layer "In6.Cu")
		(net "M_C_CPU0_SB_DQ<31>")
	)
	(segment
		(start 287.510728 -193.725292)
		(end 287.231074 -193.75755)
		(width 0.18288)
		(layer "In6.Cu")
		(net "M_C_CPU0_SB_DQ<31>")
	)
	(segment
		(start 314.81268 -199.247252)
		(end 313.797188 -199.247252)
		(width 0.18288)
		(layer "In6.Cu")
		(net "M_C_CPU0_SB_DQ<31>")
	)
	(segment
		(start 338.717636 -224.065084)
		(end 338.708746 -224.070164)
		(width 0.088646)
		(layer "In6.Cu")
		(net "M_C_CPU0_SB_DQ<31>")
	)
	(segment
		(start 341.159084 -224.404936)
		(end 341.159084 -224.389442)
		(width 0.088646)
		(layer "In6.Cu")
		(net "M_C_CPU0_SB_DQ<31>")
	)
	(segment
		(start 303.515522 -193.812668)
		(end 302.535082 -193.725292)
		(width 0.18288)
		(layer "In6.Cu")
		(net "M_C_CPU0_SB_DQ<31>")
	)
	(segment
		(start 344.826082 -227.155502)
		(end 344.733118 -227.101146)
		(width 0.088646)
		(layer "In6.Cu")
		(net "M_C_CPU0_SB_DQ<31>")
	)
	(segment
		(start 340.980522 -224.070164)
		(end 340.971632 -224.065084)
		(width 0.088646)
		(layer "In6.Cu")
		(net "M_C_CPU0_SB_DQ<31>")
	)
	(segment
		(start 304.360072 -194.208146)
		(end 304.162206 -194.374008)
		(width 0.18288)
		(layer "In6.Cu")
		(net "M_C_CPU0_SB_DQ<31>")
	)
	(segment
		(start 337.399884 -224.404936)
		(end 337.399884 -224.389442)
		(width 0.088646)
		(layer "In6.Cu")
		(net "M_C_CPU0_SB_DQ<31>")
	)
	(segment
		(start 308.168548 -194.479926)
		(end 307.890672 -194.312032)
		(width 0.18288)
		(layer "In6.Cu")
		(net "M_C_CPU0_SB_DQ<31>")
	)
	(segment
		(start 303.835054 -194.344798)
		(end 303.67097 -194.14871)
		(width 0.18288)
		(layer "In6.Cu")
		(net "M_C_CPU0_SB_DQ<31>")
	)
	(segment
		(start 284.430216 -195.616576)
		(end 283.916882 -195.616576)
		(width 0.18288)
		(layer "In6.Cu")
		(net "M_C_CPU0_SB_DQ<31>")
	)
	(segment
		(start 307.890672 -194.312032)
		(end 307.606192 -194.237864)
		(width 0.18288)
		(layer "In6.Cu")
		(net "M_C_CPU0_SB_DQ<31>")
	)
	(segment
		(start 306.813458 -194.105784)
		(end 304.570638 -193.90614)
		(width 0.18288)
		(layer "In6.Cu")
		(net "M_C_CPU0_SB_DQ<31>")
	)
	(segment
		(start 284.673294 -195.373498)
		(end 284.430216 -195.616576)
		(width 0.18288)
		(layer "In6.Cu")
		(net "M_C_CPU0_SB_DQ<31>")
	)
	(segment
		(start 287.231074 -193.75755)
		(end 285.613856 -194.083686)
		(width 0.18288)
		(layer "In6.Cu")
		(net "M_C_CPU0_SB_DQ<31>")
	)
	(segment
		(start 338.247482 -224.8789)
		(end 338.23275 -224.887536)
		(width 0.088646)
		(layer "In6.Cu")
		(net "M_C_CPU0_SB_DQ<31>")
	)
	(segment
		(start 288.474658 -193.908172)
		(end 288.291778 -193.725292)
		(width 0.18288)
		(layer "In6.Cu")
		(net "M_C_CPU0_SB_DQ<31>")
	)
	(segment
		(start 304.365406 -194.14871)
		(end 304.360072 -194.208146)
		(width 0.18288)
		(layer "In6.Cu")
		(net "M_C_CPU0_SB_DQ<31>")
	)
	(segment
		(start 341.62873 -225.217482)
		(end 341.62873 -225.203258)
		(width 0.088646)
		(layer "In6.Cu")
		(net "M_C_CPU0_SB_DQ<31>")
	)
	(segment
		(start 310.518048 -196.829426)
		(end 309.730394 -196.829426)
		(width 0.18288)
		(layer "In6.Cu")
		(net "M_C_CPU0_SB_DQ<31>")
	)
	(segment
		(start 337.212432 -224.065084)
		(end 337.20024 -224.057972)
		(width 0.088646)
		(layer "In6.Cu")
		(net "M_C_CPU0_SB_DQ<31>")
	)
	(segment
		(start 285.613856 -194.083686)
		(end 284.898084 -194.331336)
		(width 0.18288)
		(layer "In6.Cu")
		(net "M_C_CPU0_SB_DQ<31>")
	)
	(segment
		(start 304.162206 -194.374008)
		(end 303.835054 -194.344798)
		(width 0.18288)
		(layer "In6.Cu")
		(net "M_C_CPU0_SB_DQ<31>")
	)
	(segment
		(start 336.376518 -223.246442)
		(end 336.368136 -223.251268)
		(width 0.088646)
		(layer "In6.Cu")
		(net "M_C_CPU0_SB_DQ<31>")
	)
	(segment
		(start 340.597236 -224.065084)
		(end 340.588346 -224.070164)
		(width 0.088646)
		(layer "In6.Cu")
		(net "M_C_CPU0_SB_DQ<31>")
	)
	(segment
		(start 318.82334 -203.257912)
		(end 314.81268 -199.247252)
		(width 0.18288)
		(layer "In6.Cu")
		(net "M_C_CPU0_SB_DQ<31>")
	)
	(segment
		(start 291.226748 -194.118484)
		(end 291.226748 -193.908172)
		(width 0.18288)
		(layer "In6.Cu")
		(net "M_C_CPU0_SB_DQ<31>")
	)
	(segment
		(start 342.860122 -225.69805)
		(end 342.851232 -225.69297)
		(width 0.088646)
		(layer "In6.Cu")
		(net "M_C_CPU0_SB_DQ<31>")
	)
	(segment
		(start 303.67097 -194.14871)
		(end 303.669446 -194.146932)
		(width 0.18288)
		(layer "In6.Cu")
		(net "M_C_CPU0_SB_DQ<31>")
	)
	(segment
		(start 304.372264 -194.072256)
		(end 304.365406 -194.14871)
		(width 0.18288)
		(layer "In6.Cu")
		(net "M_C_CPU0_SB_DQ<31>")
	)
	(segment
		(start 339.100922 -224.070164)
		(end 339.092032 -224.065084)
		(width 0.088646)
		(layer "In6.Cu")
		(net "M_C_CPU0_SB_DQ<31>")
	)
	(segment
		(start 312.268362 -197.718426)
		(end 311.407048 -197.718426)
		(width 0.18288)
		(layer "In6.Cu")
		(net "M_C_CPU0_SB_DQ<31>")
	)
	(segment
		(start 332.70063 -222.77578)
		(end 332.70063 -221.76486)
		(width 0.088646)
		(layer "In6.Cu")
		(net "M_C_CPU0_SB_DQ<31>")
	)
	(segment
		(start 284.673294 -194.556126)
		(end 284.673294 -195.373498)
		(width 0.18288)
		(layer "In6.Cu")
		(net "M_C_CPU0_SB_DQ<31>")
	)
	(segment
		(start 341.926164 -225.701606)
		(end 341.911432 -225.69297)
		(width 0.088646)
		(layer "In6.Cu")
		(net "M_C_CPU0_SB_DQ<31>")
	)
	(segment
		(start 309.730394 -196.829426)
		(end 308.587394 -195.686426)
		(width 0.18288)
		(layer "In6.Cu")
		(net "M_C_CPU0_SB_DQ<31>")
	)
	(arc
		(start 341.911432 -225.69297)
		(mid 341.707951 -225.492166)
		(end 341.62873 -225.217482)
		(width 0.088646)
		(layer "In6.Cu")
		(net "M_C_CPU0_SB_DQ<31>")
	)
	(arc
		(start 340.409784 -224.389442)
		(mid 340.335793 -224.669008)
		(end 340.133178 -224.875344)
		(width 0.088646)
		(layer "In6.Cu")
		(net "M_C_CPU0_SB_DQ<31>")
	)
	(arc
		(start 343.320878 -226.506786)
		(mid 343.118055 -226.306555)
		(end 343.038684 -226.032822)
		(width 0.088646)
		(layer "In6.Cu")
		(net "M_C_CPU0_SB_DQ<31>")
	)
	(arc
		(start 339.092032 -224.065084)
		(mid 338.904834 -224.014941)
		(end 338.717636 -224.065084)
		(width 0.088646)
		(layer "In6.Cu")
		(net "M_C_CPU0_SB_DQ<31>")
	)
	(arc
		(start 334.488536 -223.251268)
		(mid 334.205834 -223.32701)
		(end 333.923132 -223.251268)
		(width 0.088646)
		(layer "In6.Cu")
		(net "M_C_CPU0_SB_DQ<31>")
	)
	(arc
		(start 344.733118 -227.101146)
		(mid 344.698042 -227.073952)
		(end 344.671142 -227.038662)
		(width 0.088646)
		(layer "In6.Cu")
		(net "M_C_CPU0_SB_DQ<31>")
	)
	(arc
		(start 338.530184 -224.389442)
		(mid 338.456193 -224.669008)
		(end 338.253578 -224.875344)
		(width 0.088646)
		(layer "In6.Cu")
		(net "M_C_CPU0_SB_DQ<31>")
	)
	(arc
		(start 343.876122 -226.512882)
		(mid 343.59769 -226.582728)
		(end 343.320878 -226.506786)
		(width 0.088646)
		(layer "In6.Cu")
		(net "M_C_CPU0_SB_DQ<31>")
	)
	(arc
		(start 338.708746 -224.070164)
		(mid 338.577832 -224.206524)
		(end 338.530184 -224.389442)
		(width 0.088646)
		(layer "In6.Cu")
		(net "M_C_CPU0_SB_DQ<31>")
	)
	(arc
		(start 341.62873 -225.203258)
		(mid 341.581051 -225.020358)
		(end 341.450168 -224.88398)
		(width 0.088646)
		(layer "In6.Cu")
		(net "M_C_CPU0_SB_DQ<31>")
	)
	(arc
		(start 337.20024 -224.057972)
		(mid 337.002012 -223.852124)
		(end 336.92973 -223.575626)
		(width 0.088646)
		(layer "In6.Cu")
		(net "M_C_CPU0_SB_DQ<31>")
	)
	(arc
		(start 338.23275 -224.887536)
		(mid 337.956275 -224.954856)
		(end 337.682078 -224.8789)
		(width 0.088646)
		(layer "In6.Cu")
		(net "M_C_CPU0_SB_DQ<31>")
	)
	(arc
		(start 345.200478 -227.155502)
		(mid 345.01328 -227.205645)
		(end 344.826082 -227.155502)
		(width 0.088646)
		(layer "In6.Cu")
		(net "M_C_CPU0_SB_DQ<31>")
	)
	(arc
		(start 337.399884 -224.389442)
		(mid 337.352205 -224.206542)
		(end 337.221322 -224.070164)
		(width 0.088646)
		(layer "In6.Cu")
		(net "M_C_CPU0_SB_DQ<31>")
	)
	(arc
		(start 344.260932 -226.506786)
		(mid 344.073734 -226.456643)
		(end 343.886536 -226.506786)
		(width 0.088646)
		(layer "In6.Cu")
		(net "M_C_CPU0_SB_DQ<31>")
	)
	(arc
		(start 336.353404 -223.259904)
		(mid 336.076963 -223.32707)
		(end 335.802732 -223.251268)
		(width 0.088646)
		(layer "In6.Cu")
		(net "M_C_CPU0_SB_DQ<31>")
	)
	(arc
		(start 343.038684 -226.017328)
		(mid 342.991005 -225.834428)
		(end 342.860122 -225.69805)
		(width 0.088646)
		(layer "In6.Cu")
		(net "M_C_CPU0_SB_DQ<31>")
	)
	(arc
		(start 335.428336 -223.251268)
		(mid 335.145634 -223.32701)
		(end 334.862932 -223.251268)
		(width 0.088646)
		(layer "In6.Cu")
		(net "M_C_CPU0_SB_DQ<31>")
	)
	(arc
		(start 333.923132 -223.251268)
		(mid 333.735934 -223.201125)
		(end 333.548736 -223.251268)
		(width 0.088646)
		(layer "In6.Cu")
		(net "M_C_CPU0_SB_DQ<31>")
	)
	(arc
		(start 342.476836 -225.69297)
		(mid 342.202607 -225.768895)
		(end 341.926164 -225.701606)
		(width 0.088646)
		(layer "In6.Cu")
		(net "M_C_CPU0_SB_DQ<31>")
	)
	(arc
		(start 345.95308 -226.831144)
		(mid 345.769011 -226.855368)
		(end 345.59748 -226.926394)
		(width 0.088646)
		(layer "In6.Cu")
		(net "M_C_CPU0_SB_DQ<31>")
	)
	(arc
		(start 344.504772 -226.750372)
		(mid 344.398886 -226.612526)
		(end 344.260932 -226.506786)
		(width 0.088646)
		(layer "In6.Cu")
		(net "M_C_CPU0_SB_DQ<31>")
	)
	(arc
		(start 339.561678 -224.8789)
		(mid 339.358855 -224.678669)
		(end 339.279484 -224.404936)
		(width 0.088646)
		(layer "In6.Cu")
		(net "M_C_CPU0_SB_DQ<31>")
	)
	(arc
		(start 336.92973 -223.575626)
		(mid 336.882051 -223.392726)
		(end 336.751168 -223.256348)
		(width 0.088646)
		(layer "In6.Cu")
		(net "M_C_CPU0_SB_DQ<31>")
	)
	(arc
		(start 340.971632 -224.065084)
		(mid 340.784434 -224.014941)
		(end 340.597236 -224.065084)
		(width 0.088646)
		(layer "In6.Cu")
		(net "M_C_CPU0_SB_DQ<31>")
	)
	(arc
		(start 339.279484 -224.389442)
		(mid 339.231805 -224.206542)
		(end 339.100922 -224.070164)
		(width 0.088646)
		(layer "In6.Cu")
		(net "M_C_CPU0_SB_DQ<31>")
	)
	(arc
		(start 333.548736 -223.251268)
		(mid 333.274507 -223.327193)
		(end 332.998064 -223.259904)
		(width 0.088646)
		(layer "In6.Cu")
		(net "M_C_CPU0_SB_DQ<31>")
	)
	(arc
		(start 341.159084 -224.389442)
		(mid 341.111405 -224.206542)
		(end 340.980522 -224.070164)
		(width 0.088646)
		(layer "In6.Cu")
		(net "M_C_CPU0_SB_DQ<31>")
	)
	(arc
		(start 340.11235 -224.887536)
		(mid 339.835875 -224.954856)
		(end 339.561678 -224.8789)
		(width 0.088646)
		(layer "In6.Cu")
		(net "M_C_CPU0_SB_DQ<31>")
	)
	(arc
		(start 342.851232 -225.69297)
		(mid 342.664034 -225.642827)
		(end 342.476836 -225.69297)
		(width 0.088646)
		(layer "In6.Cu")
		(net "M_C_CPU0_SB_DQ<31>")
	)
	(arc
		(start 340.588346 -224.070164)
		(mid 340.457432 -224.206524)
		(end 340.409784 -224.389442)
		(width 0.088646)
		(layer "In6.Cu")
		(net "M_C_CPU0_SB_DQ<31>")
	)
	(arc
		(start 334.862932 -223.251268)
		(mid 334.675734 -223.201125)
		(end 334.488536 -223.251268)
		(width 0.088646)
		(layer "In6.Cu")
		(net "M_C_CPU0_SB_DQ<31>")
	)
	(arc
		(start 335.802732 -223.251268)
		(mid 335.615534 -223.201125)
		(end 335.428336 -223.251268)
		(width 0.088646)
		(layer "In6.Cu")
		(net "M_C_CPU0_SB_DQ<31>")
	)
	(arc
		(start 336.742278 -223.251268)
		(mid 336.560027 -223.201157)
		(end 336.376518 -223.246442)
		(width 0.088646)
		(layer "In6.Cu")
		(net "M_C_CPU0_SB_DQ<31>")
	)
	(arc
		(start 332.983332 -223.251268)
		(mid 332.779851 -223.050464)
		(end 332.70063 -222.77578)
		(width 0.088646)
		(layer "In6.Cu")
		(net "M_C_CPU0_SB_DQ<31>")
	)
	(arc
		(start 341.441278 -224.8789)
		(mid 341.238455 -224.678669)
		(end 341.159084 -224.404936)
		(width 0.088646)
		(layer "In6.Cu")
		(net "M_C_CPU0_SB_DQ<31>")
	)
	(arc
		(start 337.682078 -224.8789)
		(mid 337.479255 -224.678669)
		(end 337.399884 -224.404936)
		(width 0.088646)
		(layer "In6.Cu")
		(net "M_C_CPU0_SB_DQ<31>")
	)
	(segment
		(start 279.912826 -196.891656)
		(end 277.852886 -196.891656)
		(width 0.1016)
		(layer "F.Cu")
		(net "M_C_CPU0_SB_DQ<30>")
	)
	(segment
		(start 277.852886 -196.891656)
		(end 277.59787 -196.891656)
		(width 0.101854)
		(layer "F.Cu")
		(net "M_C_CPU0_SB_DQ<30>")
	)
	(segment
		(start 281.285442 -197.528434)
		(end 280.856944 -197.528434)
		(width 0.20066)
		(layer "F.Cu")
		(net "M_C_CPU0_SB_DQ<30>")
	)
	(segment
		(start 277.59787 -196.891656)
		(end 277.58771 -196.881496)
		(width 0.101854)
		(layer "F.Cu")
		(net "M_C_CPU0_SB_DQ<30>")
	)
	(segment
		(start 280.689558 -197.361048)
		(end 280.689558 -197.03542)
		(width 0.20066)
		(layer "F.Cu")
		(net "M_C_CPU0_SB_DQ<30>")
	)
	(segment
		(start 276.415246 -197.316598)
		(end 275.268182 -197.316598)
		(width 0.20066)
		(layer "F.Cu")
		(net "M_C_CPU0_SB_DQ<30>")
	)
	(segment
		(start 283.916882 -197.316598)
		(end 282.811982 -197.316598)
		(width 0.20066)
		(layer "F.Cu")
		(net "M_C_CPU0_SB_DQ<30>")
	)
	(segment
		(start 282.811982 -197.316598)
		(end 281.497278 -197.316598)
		(width 0.20066)
		(layer "F.Cu")
		(net "M_C_CPU0_SB_DQ<30>")
	)
	(segment
		(start 280.856944 -197.528434)
		(end 280.689558 -197.361048)
		(width 0.20066)
		(layer "F.Cu")
		(net "M_C_CPU0_SB_DQ<30>")
	)
	(segment
		(start 343.13368 -227.36683)
		(end 343.13368 -226.831144)
		(width 0.20066)
		(layer "F.Cu")
		(net "M_C_CPU0_SB_DQ<30>")
	)
	(segment
		(start 280.689558 -197.03542)
		(end 280.545794 -196.891656)
		(width 0.20066)
		(layer "F.Cu")
		(net "M_C_CPU0_SB_DQ<30>")
	)
	(segment
		(start 277.58771 -196.881496)
		(end 276.850348 -196.881496)
		(width 0.20066)
		(layer "F.Cu")
		(net "M_C_CPU0_SB_DQ<30>")
	)
	(segment
		(start 280.545794 -196.891656)
		(end 279.912826 -196.891656)
		(width 0.20066)
		(layer "F.Cu")
		(net "M_C_CPU0_SB_DQ<30>")
	)
	(segment
		(start 281.497278 -197.316598)
		(end 281.285442 -197.528434)
		(width 0.20066)
		(layer "F.Cu")
		(net "M_C_CPU0_SB_DQ<30>")
	)
	(segment
		(start 343.133934 -227.367084)
		(end 343.13368 -227.36683)
		(width 0.20066)
		(layer "F.Cu")
		(net "M_C_CPU0_SB_DQ<30>")
	)
	(segment
		(start 276.850348 -196.881496)
		(end 276.415246 -197.316598)
		(width 0.20066)
		(layer "F.Cu")
		(net "M_C_CPU0_SB_DQ<30>")
	)
	(segment
		(start 330.41971 -221.047818)
		(end 330.23683 -221.047818)
		(width 0.18288)
		(layer "In6.Cu")
		(net "M_C_CPU0_SB_DQ<30>")
	)
	(segment
		(start 341.537036 -226.341686)
		(end 341.528146 -226.336606)
		(width 0.088646)
		(layer "In6.Cu")
		(net "M_C_CPU0_SB_DQ<30>")
	)
	(segment
		(start 290.571174 -194.458336)
		(end 290.388294 -194.275456)
		(width 0.18288)
		(layer "In6.Cu")
		(net "M_C_CPU0_SB_DQ<30>")
	)
	(segment
		(start 285.770828 -195.899532)
		(end 285.512256 -195.899532)
		(width 0.18288)
		(layer "In6.Cu")
		(net "M_C_CPU0_SB_DQ<30>")
	)
	(segment
		(start 292.966648 -195.190872)
		(end 292.103048 -195.190872)
		(width 0.18288)
		(layer "In6.Cu")
		(net "M_C_CPU0_SB_DQ<30>")
	)
	(segment
		(start 341.926164 -226.33305)
		(end 341.911432 -226.341686)
		(width 0.088646)
		(layer "In6.Cu")
		(net "M_C_CPU0_SB_DQ<30>")
	)
	(segment
		(start 286.310832 -196.180964)
		(end 286.05226 -196.180964)
		(width 0.18288)
		(layer "In6.Cu")
		(net "M_C_CPU0_SB_DQ<30>")
	)
	(segment
		(start 321.248786 -210.472528)
		(end 318.39027 -203.571602)
		(width 0.18288)
		(layer "In6.Cu")
		(net "M_C_CPU0_SB_DQ<30>")
	)
	(segment
		(start 309.85714 -197.845426)
		(end 308.23789 -196.226176)
		(width 0.18288)
		(layer "In6.Cu")
		(net "M_C_CPU0_SB_DQ<30>")
	)
	(segment
		(start 285.512256 -195.899532)
		(end 285.242762 -196.169026)
		(width 0.18288)
		(layer "In6.Cu")
		(net "M_C_CPU0_SB_DQ<30>")
	)
	(segment
		(start 285.242762 -196.169026)
		(end 284.990286 -196.169026)
		(width 0.18288)
		(layer "In6.Cu")
		(net "M_C_CPU0_SB_DQ<30>")
	)
	(segment
		(start 287.863788 -194.944746)
		(end 287.863788 -194.496944)
		(width 0.18288)
		(layer "In6.Cu")
		(net "M_C_CPU0_SB_DQ<30>")
	)
	(segment
		(start 313.592718 -199.753982)
		(end 312.573162 -198.734426)
		(width 0.18288)
		(layer "In6.Cu")
		(net "M_C_CPU0_SB_DQ<30>")
	)
	(segment
		(start 289.880294 -194.458336)
		(end 289.880294 -195.16979)
		(width 0.18288)
		(layer "In6.Cu")
		(net "M_C_CPU0_SB_DQ<30>")
	)
	(segment
		(start 330.915264 -221.047818)
		(end 330.41971 -221.047818)
		(width 0.088646)
		(layer "In6.Cu")
		(net "M_C_CPU0_SB_DQ<30>")
	)
	(segment
		(start 318.39027 -203.571602)
		(end 314.57265 -199.753982)
		(width 0.18288)
		(layer "In6.Cu")
		(net "M_C_CPU0_SB_DQ<30>")
	)
	(segment
		(start 329.994514 -220.805502)
		(end 329.994514 -219.218256)
		(width 0.18288)
		(layer "In6.Cu")
		(net "M_C_CPU0_SB_DQ<30>")
	)
	(segment
		(start 308.23789 -196.226176)
		(end 307.704744 -196.226176)
		(width 0.18288)
		(layer "In6.Cu")
		(net "M_C_CPU0_SB_DQ<30>")
	)
	(segment
		(start 287.680908 -194.314064)
		(end 287.097724 -194.314064)
		(width 0.18288)
		(layer "In6.Cu")
		(net "M_C_CPU0_SB_DQ<30>")
	)
	(segment
		(start 286.542734 -195.69049)
		(end 286.542734 -195.949062)
		(width 0.18288)
		(layer "In6.Cu")
		(net "M_C_CPU0_SB_DQ<30>")
	)
	(segment
		(start 332.998064 -223.891348)
		(end 332.983332 -223.899984)
		(width 0.088646)
		(layer "In6.Cu")
		(net "M_C_CPU0_SB_DQ<30>")
	)
	(segment
		(start 305.876706 -195.432426)
		(end 305.693826 -195.249546)
		(width 0.18288)
		(layer "In6.Cu")
		(net "M_C_CPU0_SB_DQ<30>")
	)
	(segment
		(start 288.046668 -195.127626)
		(end 287.863788 -194.944746)
		(width 0.18288)
		(layer "In6.Cu")
		(net "M_C_CPU0_SB_DQ<30>")
	)
	(segment
		(start 289.880294 -195.16979)
		(end 289.697414 -195.35267)
		(width 0.18288)
		(layer "In6.Cu")
		(net "M_C_CPU0_SB_DQ<30>")
	)
	(segment
		(start 310.492394 -197.845426)
		(end 309.85714 -197.845426)
		(width 0.18288)
		(layer "In6.Cu")
		(net "M_C_CPU0_SB_DQ<30>")
	)
	(segment
		(start 312.573162 -198.734426)
		(end 311.381394 -198.734426)
		(width 0.18288)
		(layer "In6.Cu")
		(net "M_C_CPU0_SB_DQ<30>")
	)
	(segment
		(start 286.542734 -195.949062)
		(end 286.310832 -196.180964)
		(width 0.18288)
		(layer "In6.Cu")
		(net "M_C_CPU0_SB_DQ<30>")
	)
	(segment
		(start 341.349584 -226.017328)
		(end 341.349584 -226.003104)
		(width 0.088646)
		(layer "In6.Cu")
		(net "M_C_CPU0_SB_DQ<30>")
	)
	(segment
		(start 337.120484 -225.211894)
		(end 337.120484 -225.193352)
		(width 0.088646)
		(layer "In6.Cu")
		(net "M_C_CPU0_SB_DQ<30>")
	)
	(segment
		(start 289.697414 -195.35267)
		(end 289.006534 -195.35267)
		(width 0.18288)
		(layer "In6.Cu")
		(net "M_C_CPU0_SB_DQ<30>")
	)
	(segment
		(start 304.820066 -195.432426)
		(end 303.989994 -195.432426)
		(width 0.18288)
		(layer "In6.Cu")
		(net "M_C_CPU0_SB_DQ<30>")
	)
	(segment
		(start 283.916882 -197.24243)
		(end 283.916882 -197.316598)
		(width 0.18288)
		(layer "In6.Cu")
		(net "M_C_CPU0_SB_DQ<30>")
	)
	(segment
		(start 331.951584 -222.084138)
		(end 330.915264 -221.047818)
		(width 0.088646)
		(layer "In6.Cu")
		(net "M_C_CPU0_SB_DQ<30>")
	)
	(segment
		(start 290.063174 -194.275456)
		(end 289.880294 -194.458336)
		(width 0.18288)
		(layer "In6.Cu")
		(net "M_C_CPU0_SB_DQ<30>")
	)
	(segment
		(start 307.704744 -196.226176)
		(end 306.910994 -195.432426)
		(width 0.18288)
		(layer "In6.Cu")
		(net "M_C_CPU0_SB_DQ<30>")
	)
	(segment
		(start 338.247482 -225.527616)
		(end 338.23275 -225.51898)
		(width 0.088646)
		(layer "In6.Cu")
		(net "M_C_CPU0_SB_DQ<30>")
	)
	(segment
		(start 284.990286 -196.169026)
		(end 283.916882 -197.24243)
		(width 0.18288)
		(layer "In6.Cu")
		(net "M_C_CPU0_SB_DQ<30>")
	)
	(segment
		(start 287.863788 -194.496944)
		(end 287.680908 -194.314064)
		(width 0.18288)
		(layer "In6.Cu")
		(net "M_C_CPU0_SB_DQ<30>")
	)
	(segment
		(start 332.617572 -223.90481)
		(end 332.60919 -223.899984)
		(width 0.088646)
		(layer "In6.Cu")
		(net "M_C_CPU0_SB_DQ<30>")
	)
	(segment
		(start 336.367882 -223.899984)
		(end 336.357468 -223.893888)
		(width 0.088646)
		(layer "In6.Cu")
		(net "M_C_CPU0_SB_DQ<30>")
	)
	(segment
		(start 286.261302 -195.409058)
		(end 286.542734 -195.69049)
		(width 0.18288)
		(layer "In6.Cu")
		(net "M_C_CPU0_SB_DQ<30>")
	)
	(segment
		(start 302.505872 -194.238626)
		(end 293.918894 -194.238626)
		(width 0.18288)
		(layer "In6.Cu")
		(net "M_C_CPU0_SB_DQ<30>")
	)
	(segment
		(start 305.002946 -195.249546)
		(end 304.820066 -195.432426)
		(width 0.18288)
		(layer "In6.Cu")
		(net "M_C_CPU0_SB_DQ<30>")
	)
	(segment
		(start 305.693826 -194.790568)
		(end 305.510946 -194.607688)
		(width 0.18288)
		(layer "In6.Cu")
		(net "M_C_CPU0_SB_DQ<30>")
	)
	(segment
		(start 305.002946 -194.790568)
		(end 305.002946 -195.249546)
		(width 0.18288)
		(layer "In6.Cu")
		(net "M_C_CPU0_SB_DQ<30>")
	)
	(segment
		(start 290.754054 -195.35267)
		(end 290.571174 -195.16979)
		(width 0.18288)
		(layer "In6.Cu")
		(net "M_C_CPU0_SB_DQ<30>")
	)
	(segment
		(start 314.57265 -199.753982)
		(end 313.592718 -199.753982)
		(width 0.18288)
		(layer "In6.Cu")
		(net "M_C_CPU0_SB_DQ<30>")
	)
	(segment
		(start 331.951584 -223.26092)
		(end 331.951584 -222.084138)
		(width 0.088646)
		(layer "In6.Cu")
		(net "M_C_CPU0_SB_DQ<30>")
	)
	(segment
		(start 288.78149 -195.127626)
		(end 288.046668 -195.127626)
		(width 0.18288)
		(layer "In6.Cu")
		(net "M_C_CPU0_SB_DQ<30>")
	)
	(segment
		(start 336.838036 -224.7138)
		(end 336.829146 -224.70872)
		(width 0.088646)
		(layer "In6.Cu")
		(net "M_C_CPU0_SB_DQ<30>")
	)
	(segment
		(start 305.185826 -194.607688)
		(end 305.002946 -194.790568)
		(width 0.18288)
		(layer "In6.Cu")
		(net "M_C_CPU0_SB_DQ<30>")
	)
	(segment
		(start 332.531212 -223.840548)
		(end 331.951584 -223.26092)
		(width 0.088646)
		(layer "In6.Cu")
		(net "M_C_CPU0_SB_DQ<30>")
	)
	(segment
		(start 341.066882 -225.527616)
		(end 341.05215 -225.51898)
		(width 0.088646)
		(layer "In6.Cu")
		(net "M_C_CPU0_SB_DQ<30>")
	)
	(segment
		(start 343.13368 -226.831144)
		(end 342.821006 -226.831144)
		(width 0.088646)
		(layer "In6.Cu")
		(net "M_C_CPU0_SB_DQ<30>")
	)
	(segment
		(start 289.006534 -195.35267)
		(end 288.78149 -195.127626)
		(width 0.18288)
		(layer "In6.Cu")
		(net "M_C_CPU0_SB_DQ<30>")
	)
	(segment
		(start 287.097724 -194.314064)
		(end 286.261302 -195.150486)
		(width 0.18288)
		(layer "In6.Cu")
		(net "M_C_CPU0_SB_DQ<30>")
	)
	(segment
		(start 303.989994 -195.432426)
		(end 303.001426 -194.443858)
		(width 0.18288)
		(layer "In6.Cu")
		(net "M_C_CPU0_SB_DQ<30>")
	)
	(segment
		(start 303.001426 -194.443858)
		(end 302.505872 -194.238626)
		(width 0.18288)
		(layer "In6.Cu")
		(net "M_C_CPU0_SB_DQ<30>")
	)
	(segment
		(start 306.910994 -195.432426)
		(end 305.876706 -195.432426)
		(width 0.18288)
		(layer "In6.Cu")
		(net "M_C_CPU0_SB_DQ<30>")
	)
	(segment
		(start 342.821006 -226.831144)
		(end 342.755474 -226.765612)
		(width 0.088646)
		(layer "In6.Cu")
		(net "M_C_CPU0_SB_DQ<30>")
	)
	(segment
		(start 305.510946 -194.607688)
		(end 305.185826 -194.607688)
		(width 0.18288)
		(layer "In6.Cu")
		(net "M_C_CPU0_SB_DQ<30>")
	)
	(segment
		(start 305.693826 -195.249546)
		(end 305.693826 -194.790568)
		(width 0.18288)
		(layer "In6.Cu")
		(net "M_C_CPU0_SB_DQ<30>")
	)
	(segment
		(start 293.918894 -194.238626)
		(end 292.966648 -195.190872)
		(width 0.18288)
		(layer "In6.Cu")
		(net "M_C_CPU0_SB_DQ<30>")
	)
	(segment
		(start 329.994514 -219.218256)
		(end 321.248786 -210.472528)
		(width 0.18288)
		(layer "In6.Cu")
		(net "M_C_CPU0_SB_DQ<30>")
	)
	(segment
		(start 291.94125 -195.35267)
		(end 290.754054 -195.35267)
		(width 0.18288)
		(layer "In6.Cu")
		(net "M_C_CPU0_SB_DQ<30>")
	)
	(segment
		(start 311.381394 -198.734426)
		(end 310.492394 -197.845426)
		(width 0.18288)
		(layer "In6.Cu")
		(net "M_C_CPU0_SB_DQ<30>")
	)
	(segment
		(start 290.388294 -194.275456)
		(end 290.063174 -194.275456)
		(width 0.18288)
		(layer "In6.Cu")
		(net "M_C_CPU0_SB_DQ<30>")
	)
	(segment
		(start 286.261302 -195.150486)
		(end 286.261302 -195.409058)
		(width 0.18288)
		(layer "In6.Cu")
		(net "M_C_CPU0_SB_DQ<30>")
	)
	(segment
		(start 340.127082 -225.527616)
		(end 340.11235 -225.51898)
		(width 0.088646)
		(layer "In6.Cu")
		(net "M_C_CPU0_SB_DQ<30>")
	)
	(segment
		(start 336.373978 -223.90354)
		(end 336.367882 -223.899984)
		(width 0.088646)
		(layer "In6.Cu")
		(net "M_C_CPU0_SB_DQ<30>")
	)
	(segment
		(start 290.571174 -195.16979)
		(end 290.571174 -194.458336)
		(width 0.18288)
		(layer "In6.Cu")
		(net "M_C_CPU0_SB_DQ<30>")
	)
	(segment
		(start 286.05226 -196.180964)
		(end 285.770828 -195.899532)
		(width 0.18288)
		(layer "In6.Cu")
		(net "M_C_CPU0_SB_DQ<30>")
	)
	(segment
		(start 292.103048 -195.190872)
		(end 291.94125 -195.35267)
		(width 0.18288)
		(layer "In6.Cu")
		(net "M_C_CPU0_SB_DQ<30>")
	)
	(segment
		(start 330.23683 -221.047818)
		(end 329.994514 -220.805502)
		(width 0.18288)
		(layer "In6.Cu")
		(net "M_C_CPU0_SB_DQ<30>")
	)
	(arc
		(start 335.802732 -223.899984)
		(mid 335.615534 -223.950127)
		(end 335.428336 -223.899984)
		(width 0.088646)
		(layer "In6.Cu")
		(net "M_C_CPU0_SB_DQ<30>")
	)
	(arc
		(start 339.187282 -225.527616)
		(mid 338.90458 -225.451874)
		(end 338.621878 -225.527616)
		(width 0.088646)
		(layer "In6.Cu")
		(net "M_C_CPU0_SB_DQ<30>")
	)
	(arc
		(start 332.983332 -223.899984)
		(mid 332.801081 -223.950095)
		(end 332.617572 -223.90481)
		(width 0.088646)
		(layer "In6.Cu")
		(net "M_C_CPU0_SB_DQ<30>")
	)
	(arc
		(start 334.488536 -223.899984)
		(mid 334.205834 -223.824208)
		(end 333.923132 -223.899984)
		(width 0.088646)
		(layer "In6.Cu")
		(net "M_C_CPU0_SB_DQ<30>")
	)
	(arc
		(start 336.357468 -223.893888)
		(mid 336.07929 -223.824165)
		(end 335.802732 -223.899984)
		(width 0.088646)
		(layer "In6.Cu")
		(net "M_C_CPU0_SB_DQ<30>")
	)
	(arc
		(start 333.548736 -223.899984)
		(mid 333.274537 -223.824149)
		(end 332.998064 -223.891348)
		(width 0.088646)
		(layer "In6.Cu")
		(net "M_C_CPU0_SB_DQ<30>")
	)
	(arc
		(start 336.650584 -224.389442)
		(mid 336.576593 -224.109876)
		(end 336.373978 -223.90354)
		(width 0.088646)
		(layer "In6.Cu")
		(net "M_C_CPU0_SB_DQ<30>")
	)
	(arc
		(start 338.621878 -225.527616)
		(mid 338.43468 -225.577759)
		(end 338.247482 -225.527616)
		(width 0.088646)
		(layer "In6.Cu")
		(net "M_C_CPU0_SB_DQ<30>")
	)
	(arc
		(start 340.501478 -225.527616)
		(mid 340.31428 -225.577759)
		(end 340.127082 -225.527616)
		(width 0.088646)
		(layer "In6.Cu")
		(net "M_C_CPU0_SB_DQ<30>")
	)
	(arc
		(start 336.829146 -224.70872)
		(mid 336.698232 -224.57236)
		(end 336.650584 -224.389442)
		(width 0.088646)
		(layer "In6.Cu")
		(net "M_C_CPU0_SB_DQ<30>")
	)
	(arc
		(start 334.862932 -223.899984)
		(mid 334.675734 -223.950127)
		(end 334.488536 -223.899984)
		(width 0.088646)
		(layer "In6.Cu")
		(net "M_C_CPU0_SB_DQ<30>")
	)
	(arc
		(start 337.120484 -225.193352)
		(mid 337.042373 -224.916403)
		(end 336.838036 -224.7138)
		(width 0.088646)
		(layer "In6.Cu")
		(net "M_C_CPU0_SB_DQ<30>")
	)
	(arc
		(start 337.682078 -225.527616)
		(mid 337.49488 -225.577759)
		(end 337.307682 -225.527616)
		(width 0.088646)
		(layer "In6.Cu")
		(net "M_C_CPU0_SB_DQ<30>")
	)
	(arc
		(start 332.60919 -223.899984)
		(mid 332.568261 -223.872813)
		(end 332.531212 -223.840548)
		(width 0.088646)
		(layer "In6.Cu")
		(net "M_C_CPU0_SB_DQ<30>")
	)
	(arc
		(start 341.911432 -226.341686)
		(mid 341.724234 -226.391829)
		(end 341.537036 -226.341686)
		(width 0.088646)
		(layer "In6.Cu")
		(net "M_C_CPU0_SB_DQ<30>")
	)
	(arc
		(start 339.561678 -225.527616)
		(mid 339.37448 -225.577759)
		(end 339.187282 -225.527616)
		(width 0.088646)
		(layer "In6.Cu")
		(net "M_C_CPU0_SB_DQ<30>")
	)
	(arc
		(start 341.05215 -225.51898)
		(mid 340.775709 -225.451814)
		(end 340.501478 -225.527616)
		(width 0.088646)
		(layer "In6.Cu")
		(net "M_C_CPU0_SB_DQ<30>")
	)
	(arc
		(start 333.923132 -223.899984)
		(mid 333.735934 -223.950127)
		(end 333.548736 -223.899984)
		(width 0.088646)
		(layer "In6.Cu")
		(net "M_C_CPU0_SB_DQ<30>")
	)
	(arc
		(start 340.11235 -225.51898)
		(mid 339.835909 -225.451814)
		(end 339.561678 -225.527616)
		(width 0.088646)
		(layer "In6.Cu")
		(net "M_C_CPU0_SB_DQ<30>")
	)
	(arc
		(start 342.476836 -226.341686)
		(mid 342.202637 -226.265851)
		(end 341.926164 -226.33305)
		(width 0.088646)
		(layer "In6.Cu")
		(net "M_C_CPU0_SB_DQ<30>")
	)
	(arc
		(start 338.23275 -225.51898)
		(mid 337.956309 -225.451814)
		(end 337.682078 -225.527616)
		(width 0.088646)
		(layer "In6.Cu")
		(net "M_C_CPU0_SB_DQ<30>")
	)
	(arc
		(start 335.428336 -223.899984)
		(mid 335.145634 -223.824208)
		(end 334.862932 -223.899984)
		(width 0.088646)
		(layer "In6.Cu")
		(net "M_C_CPU0_SB_DQ<30>")
	)
	(arc
		(start 342.755474 -226.765612)
		(mid 342.666386 -226.520627)
		(end 342.476836 -226.341686)
		(width 0.088646)
		(layer "In6.Cu")
		(net "M_C_CPU0_SB_DQ<30>")
	)
	(arc
		(start 341.349584 -226.003104)
		(mid 341.270365 -225.728419)
		(end 341.066882 -225.527616)
		(width 0.088646)
		(layer "In6.Cu")
		(net "M_C_CPU0_SB_DQ<30>")
	)
	(arc
		(start 337.307682 -225.527616)
		(mid 337.172749 -225.394262)
		(end 337.120484 -225.211894)
		(width 0.088646)
		(layer "In6.Cu")
		(net "M_C_CPU0_SB_DQ<30>")
	)
	(arc
		(start 341.528146 -226.336606)
		(mid 341.397232 -226.200246)
		(end 341.349584 -226.017328)
		(width 0.088646)
		(layer "In6.Cu")
		(net "M_C_CPU0_SB_DQ<30>")
	)
	(segment
		(start 344.543634 -244.45849)
		(end 344.543634 -243.922804)
		(width 0.20066)
		(layer "F.Cu")
		(net "M_C_CPU0_SB_DQ<2>")
	)
	(segment
		(start 281.285442 -231.52862)
		(end 280.856944 -231.52862)
		(width 0.20066)
		(layer "F.Cu")
		(net "M_C_CPU0_SB_DQ<2>")
	)
	(segment
		(start 280.689558 -231.361234)
		(end 280.689558 -231.035606)
		(width 0.20066)
		(layer "F.Cu")
		(net "M_C_CPU0_SB_DQ<2>")
	)
	(segment
		(start 277.852886 -230.891842)
		(end 277.59787 -230.891842)
		(width 0.101854)
		(layer "F.Cu")
		(net "M_C_CPU0_SB_DQ<2>")
	)
	(segment
		(start 281.497278 -231.316784)
		(end 281.285442 -231.52862)
		(width 0.20066)
		(layer "F.Cu")
		(net "M_C_CPU0_SB_DQ<2>")
	)
	(segment
		(start 277.58771 -230.881682)
		(end 276.850348 -230.881682)
		(width 0.20066)
		(layer "F.Cu")
		(net "M_C_CPU0_SB_DQ<2>")
	)
	(segment
		(start 279.912826 -230.891842)
		(end 277.852886 -230.891842)
		(width 0.1016)
		(layer "F.Cu")
		(net "M_C_CPU0_SB_DQ<2>")
	)
	(segment
		(start 344.54338 -244.458744)
		(end 344.543634 -244.45849)
		(width 0.20066)
		(layer "F.Cu")
		(net "M_C_CPU0_SB_DQ<2>")
	)
	(segment
		(start 276.415246 -231.316784)
		(end 275.268182 -231.316784)
		(width 0.20066)
		(layer "F.Cu")
		(net "M_C_CPU0_SB_DQ<2>")
	)
	(segment
		(start 280.545794 -230.891842)
		(end 279.912826 -230.891842)
		(width 0.20066)
		(layer "F.Cu")
		(net "M_C_CPU0_SB_DQ<2>")
	)
	(segment
		(start 276.850348 -230.881682)
		(end 276.415246 -231.316784)
		(width 0.20066)
		(layer "F.Cu")
		(net "M_C_CPU0_SB_DQ<2>")
	)
	(segment
		(start 280.856944 -231.52862)
		(end 280.689558 -231.361234)
		(width 0.20066)
		(layer "F.Cu")
		(net "M_C_CPU0_SB_DQ<2>")
	)
	(segment
		(start 280.689558 -231.035606)
		(end 280.545794 -230.891842)
		(width 0.20066)
		(layer "F.Cu")
		(net "M_C_CPU0_SB_DQ<2>")
	)
	(segment
		(start 282.811982 -231.316784)
		(end 281.497278 -231.316784)
		(width 0.20066)
		(layer "F.Cu")
		(net "M_C_CPU0_SB_DQ<2>")
	)
	(segment
		(start 277.59787 -230.891842)
		(end 277.58771 -230.881682)
		(width 0.101854)
		(layer "F.Cu")
		(net "M_C_CPU0_SB_DQ<2>")
	)
	(segment
		(start 283.916882 -231.316784)
		(end 282.811982 -231.316784)
		(width 0.20066)
		(layer "F.Cu")
		(net "M_C_CPU0_SB_DQ<2>")
	)
	(segment
		(start 307.19649 -237.936786)
		(end 306.32273 -237.063026)
		(width 0.18288)
		(layer "In6.Cu")
		(net "M_C_CPU0_SB_DQ<2>")
	)
	(segment
		(start 341.921846 -244.241066)
		(end 341.911432 -244.247162)
		(width 0.088646)
		(layer "In6.Cu")
		(net "M_C_CPU0_SB_DQ<2>")
	)
	(segment
		(start 288.4551 -233.342434)
		(end 287.524444 -232.411778)
		(width 0.18288)
		(layer "In6.Cu")
		(net "M_C_CPU0_SB_DQ<2>")
	)
	(segment
		(start 306.32273 -237.063026)
		(end 301.768256 -237.063026)
		(width 0.18288)
		(layer "In6.Cu")
		(net "M_C_CPU0_SB_DQ<2>")
	)
	(segment
		(start 343.689686 -243.47678)
		(end 343.65311 -243.47678)
		(width 0.088646)
		(layer "In6.Cu")
		(net "M_C_CPU0_SB_DQ<2>")
	)
	(segment
		(start 290.11626 -235.463588)
		(end 290.11626 -235.205016)
		(width 0.18288)
		(layer "In6.Cu")
		(net "M_C_CPU0_SB_DQ<2>")
	)
	(segment
		(start 290.096448 -234.247436)
		(end 289.627564 -234.71632)
		(width 0.18288)
		(layer "In6.Cu")
		(net "M_C_CPU0_SB_DQ<2>")
	)
	(segment
		(start 301.768256 -237.063026)
		(end 301.585376 -236.880146)
		(width 0.18288)
		(layer "In6.Cu")
		(net "M_C_CPU0_SB_DQ<2>")
	)
	(segment
		(start 300.020736 -237.063026)
		(end 299.392086 -237.691676)
		(width 0.18288)
		(layer "In6.Cu")
		(net "M_C_CPU0_SB_DQ<2>")
	)
	(segment
		(start 290.644326 -235.991654)
		(end 290.11626 -235.463588)
		(width 0.18288)
		(layer "In6.Cu")
		(net "M_C_CPU0_SB_DQ<2>")
	)
	(segment
		(start 289.627564 -234.71632)
		(end 289.368992 -234.71632)
		(width 0.18288)
		(layer "In6.Cu")
		(net "M_C_CPU0_SB_DQ<2>")
	)
	(segment
		(start 318.553592 -242.930172)
		(end 314.818776 -239.195356)
		(width 0.18288)
		(layer "In6.Cu")
		(net "M_C_CPU0_SB_DQ<2>")
	)
	(segment
		(start 297.744134 -237.362746)
		(end 297.485562 -237.362746)
		(width 0.18288)
		(layer "In6.Cu")
		(net "M_C_CPU0_SB_DQ<2>")
	)
	(segment
		(start 286.311594 -231.867964)
		(end 284.468062 -231.867964)
		(width 0.18288)
		(layer "In6.Cu")
		(net "M_C_CPU0_SB_DQ<2>")
	)
	(segment
		(start 284.468062 -231.867964)
		(end 283.916882 -231.316784)
		(width 0.18288)
		(layer "In6.Cu")
		(net "M_C_CPU0_SB_DQ<2>")
	)
	(segment
		(start 300.894496 -236.427772)
		(end 300.894496 -236.880146)
		(width 0.18288)
		(layer "In6.Cu")
		(net "M_C_CPU0_SB_DQ<2>")
	)
	(segment
		(start 299.392086 -237.691676)
		(end 298.742862 -237.691676)
		(width 0.18288)
		(layer "In6.Cu")
		(net "M_C_CPU0_SB_DQ<2>")
	)
	(segment
		(start 290.11626 -235.205016)
		(end 290.585144 -234.736132)
		(width 0.18288)
		(layer "In6.Cu")
		(net "M_C_CPU0_SB_DQ<2>")
	)
	(segment
		(start 298.742862 -237.691676)
		(end 298.208446 -237.15726)
		(width 0.18288)
		(layer "In6.Cu")
		(net "M_C_CPU0_SB_DQ<2>")
	)
	(segment
		(start 339.106764 -244.238526)
		(end 339.092032 -244.247162)
		(width 0.088646)
		(layer "In6.Cu")
		(net "M_C_CPU0_SB_DQ<2>")
	)
	(segment
		(start 312.585862 -238.612426)
		(end 311.448196 -238.612426)
		(width 0.18288)
		(layer "In6.Cu")
		(net "M_C_CPU0_SB_DQ<2>")
	)
	(segment
		(start 342.859868 -244.242082)
		(end 342.850978 -244.247162)
		(width 0.088646)
		(layer "In6.Cu")
		(net "M_C_CPU0_SB_DQ<2>")
	)
	(segment
		(start 293.409624 -235.991654)
		(end 293.102792 -235.684822)
		(width 0.18288)
		(layer "In6.Cu")
		(net "M_C_CPU0_SB_DQ<2>")
	)
	(segment
		(start 290.35502 -234.247436)
		(end 290.096448 -234.247436)
		(width 0.18288)
		(layer "In6.Cu")
		(net "M_C_CPU0_SB_DQ<2>")
	)
	(segment
		(start 344.54338 -243.922804)
		(end 344.385646 -243.76507)
		(width 0.088646)
		(layer "In6.Cu")
		(net "M_C_CPU0_SB_DQ<2>")
	)
	(segment
		(start 311.448196 -238.612426)
		(end 310.772556 -237.936786)
		(width 0.18288)
		(layer "In6.Cu")
		(net "M_C_CPU0_SB_DQ<2>")
	)
	(segment
		(start 329.567032 -242.930172)
		(end 318.553592 -242.930172)
		(width 0.18288)
		(layer "In6.Cu")
		(net "M_C_CPU0_SB_DQ<2>")
	)
	(segment
		(start 297.04284 -235.991654)
		(end 293.409624 -235.991654)
		(width 0.18288)
		(layer "In6.Cu")
		(net "M_C_CPU0_SB_DQ<2>")
	)
	(segment
		(start 331.029564 -243.966746)
		(end 330.603606 -243.966746)
		(width 0.18288)
		(layer "In6.Cu")
		(net "M_C_CPU0_SB_DQ<2>")
	)
	(segment
		(start 297.949874 -237.15726)
		(end 297.744134 -237.362746)
		(width 0.18288)
		(layer "In6.Cu")
		(net "M_C_CPU0_SB_DQ<2>")
	)
	(segment
		(start 344.543634 -243.922804)
		(end 344.54338 -243.922804)
		(width 0.088646)
		(layer "In6.Cu")
		(net "M_C_CPU0_SB_DQ<2>")
	)
	(segment
		(start 297.255438 -236.87405)
		(end 297.461178 -236.66831)
		(width 0.18288)
		(layer "In6.Cu")
		(net "M_C_CPU0_SB_DQ<2>")
	)
	(segment
		(start 332.189328 -244.206014)
		(end 331.95006 -243.966746)
		(width 0.088646)
		(layer "In6.Cu")
		(net "M_C_CPU0_SB_DQ<2>")
	)
	(segment
		(start 297.461178 -236.66831)
		(end 297.461178 -236.409992)
		(width 0.18288)
		(layer "In6.Cu")
		(net "M_C_CPU0_SB_DQ<2>")
	)
	(segment
		(start 288.4551 -233.802428)
		(end 288.4551 -233.342434)
		(width 0.18288)
		(layer "In6.Cu")
		(net "M_C_CPU0_SB_DQ<2>")
	)
	(segment
		(start 300.894496 -236.880146)
		(end 300.711616 -237.063026)
		(width 0.18288)
		(layer "In6.Cu")
		(net "M_C_CPU0_SB_DQ<2>")
	)
	(segment
		(start 343.203784 -243.662962)
		(end 343.03843 -243.828316)
		(width 0.088646)
		(layer "In6.Cu")
		(net "M_C_CPU0_SB_DQ<2>")
	)
	(segment
		(start 297.255438 -237.132622)
		(end 297.255438 -236.87405)
		(width 0.18288)
		(layer "In6.Cu")
		(net "M_C_CPU0_SB_DQ<2>")
	)
	(segment
		(start 335.342992 -244.241066)
		(end 335.332578 -244.247162)
		(width 0.088646)
		(layer "In6.Cu")
		(net "M_C_CPU0_SB_DQ<2>")
	)
	(segment
		(start 331.95006 -243.966746)
		(end 331.029564 -243.966746)
		(width 0.088646)
		(layer "In6.Cu")
		(net "M_C_CPU0_SB_DQ<2>")
	)
	(segment
		(start 330.603606 -243.966746)
		(end 329.567032 -242.930172)
		(width 0.18288)
		(layer "In6.Cu")
		(net "M_C_CPU0_SB_DQ<2>")
	)
	(segment
		(start 293.102792 -235.684822)
		(end 292.718744 -235.684822)
		(width 0.18288)
		(layer "In6.Cu")
		(net "M_C_CPU0_SB_DQ<2>")
	)
	(segment
		(start 301.077376 -236.244892)
		(end 300.894496 -236.427772)
		(width 0.18288)
		(layer "In6.Cu")
		(net "M_C_CPU0_SB_DQ<2>")
	)
	(segment
		(start 337.227164 -244.238526)
		(end 337.212432 -244.247162)
		(width 0.088646)
		(layer "In6.Cu")
		(net "M_C_CPU0_SB_DQ<2>")
	)
	(segment
		(start 336.287364 -244.238526)
		(end 336.272632 -244.247162)
		(width 0.088646)
		(layer "In6.Cu")
		(net "M_C_CPU0_SB_DQ<2>")
	)
	(segment
		(start 301.585376 -236.427772)
		(end 301.402496 -236.244892)
		(width 0.18288)
		(layer "In6.Cu")
		(net "M_C_CPU0_SB_DQ<2>")
	)
	(segment
		(start 292.718744 -235.684822)
		(end 292.411912 -235.991654)
		(width 0.18288)
		(layer "In6.Cu")
		(net "M_C_CPU0_SB_DQ<2>")
	)
	(segment
		(start 340.986364 -244.238526)
		(end 340.971632 -244.247162)
		(width 0.088646)
		(layer "In6.Cu")
		(net "M_C_CPU0_SB_DQ<2>")
	)
	(segment
		(start 290.585144 -234.736132)
		(end 290.585144 -234.47756)
		(width 0.18288)
		(layer "In6.Cu")
		(net "M_C_CPU0_SB_DQ<2>")
	)
	(segment
		(start 297.461178 -236.409992)
		(end 297.04284 -235.991654)
		(width 0.18288)
		(layer "In6.Cu")
		(net "M_C_CPU0_SB_DQ<2>")
	)
	(segment
		(start 332.599792 -244.206014)
		(end 332.189328 -244.206014)
		(width 0.088646)
		(layer "In6.Cu")
		(net "M_C_CPU0_SB_DQ<2>")
	)
	(segment
		(start 297.485562 -237.362746)
		(end 297.255438 -237.132622)
		(width 0.18288)
		(layer "In6.Cu")
		(net "M_C_CPU0_SB_DQ<2>")
	)
	(segment
		(start 343.03843 -243.828316)
		(end 343.03843 -243.922804)
		(width 0.088646)
		(layer "In6.Cu")
		(net "M_C_CPU0_SB_DQ<2>")
	)
	(segment
		(start 298.208446 -237.15726)
		(end 297.949874 -237.15726)
		(width 0.18288)
		(layer "In6.Cu")
		(net "M_C_CPU0_SB_DQ<2>")
	)
	(segment
		(start 290.585144 -234.47756)
		(end 290.35502 -234.247436)
		(width 0.18288)
		(layer "In6.Cu")
		(net "M_C_CPU0_SB_DQ<2>")
	)
	(segment
		(start 313.168792 -239.195356)
		(end 312.585862 -238.612426)
		(width 0.18288)
		(layer "In6.Cu")
		(net "M_C_CPU0_SB_DQ<2>")
	)
	(segment
		(start 300.711616 -237.063026)
		(end 300.020736 -237.063026)
		(width 0.18288)
		(layer "In6.Cu")
		(net "M_C_CPU0_SB_DQ<2>")
	)
	(segment
		(start 292.411912 -235.991654)
		(end 290.644326 -235.991654)
		(width 0.18288)
		(layer "In6.Cu")
		(net "M_C_CPU0_SB_DQ<2>")
	)
	(segment
		(start 286.855408 -232.411778)
		(end 286.311594 -231.867964)
		(width 0.18288)
		(layer "In6.Cu")
		(net "M_C_CPU0_SB_DQ<2>")
	)
	(segment
		(start 287.524444 -232.411778)
		(end 286.855408 -232.411778)
		(width 0.18288)
		(layer "In6.Cu")
		(net "M_C_CPU0_SB_DQ<2>")
	)
	(segment
		(start 310.772556 -237.936786)
		(end 307.19649 -237.936786)
		(width 0.18288)
		(layer "In6.Cu")
		(net "M_C_CPU0_SB_DQ<2>")
	)
	(segment
		(start 301.585376 -236.880146)
		(end 301.585376 -236.427772)
		(width 0.18288)
		(layer "In6.Cu")
		(net "M_C_CPU0_SB_DQ<2>")
	)
	(segment
		(start 301.402496 -236.244892)
		(end 301.077376 -236.244892)
		(width 0.18288)
		(layer "In6.Cu")
		(net "M_C_CPU0_SB_DQ<2>")
	)
	(segment
		(start 314.818776 -239.195356)
		(end 313.168792 -239.195356)
		(width 0.18288)
		(layer "In6.Cu")
		(net "M_C_CPU0_SB_DQ<2>")
	)
	(segment
		(start 289.368992 -234.71632)
		(end 288.4551 -233.802428)
		(width 0.18288)
		(layer "In6.Cu")
		(net "M_C_CPU0_SB_DQ<2>")
	)
	(arc
		(start 339.092032 -244.247162)
		(mid 338.904834 -244.297305)
		(end 338.717636 -244.247162)
		(width 0.088646)
		(layer "In6.Cu")
		(net "M_C_CPU0_SB_DQ<2>")
	)
	(arc
		(start 342.850978 -244.247162)
		(mid 342.66378 -244.297305)
		(end 342.476582 -244.247162)
		(width 0.088646)
		(layer "In6.Cu")
		(net "M_C_CPU0_SB_DQ<2>")
	)
	(arc
		(start 342.476582 -244.247162)
		(mid 342.200023 -244.171419)
		(end 341.921846 -244.241066)
		(width 0.088646)
		(layer "In6.Cu")
		(net "M_C_CPU0_SB_DQ<2>")
	)
	(arc
		(start 335.898236 -244.247162)
		(mid 335.621423 -244.171292)
		(end 335.342992 -244.241066)
		(width 0.088646)
		(layer "In6.Cu")
		(net "M_C_CPU0_SB_DQ<2>")
	)
	(arc
		(start 336.838036 -244.247162)
		(mid 336.563837 -244.171327)
		(end 336.287364 -244.238526)
		(width 0.088646)
		(layer "In6.Cu")
		(net "M_C_CPU0_SB_DQ<2>")
	)
	(arc
		(start 340.031832 -244.247162)
		(mid 339.844634 -244.297305)
		(end 339.657436 -244.247162)
		(width 0.088646)
		(layer "In6.Cu")
		(net "M_C_CPU0_SB_DQ<2>")
	)
	(arc
		(start 334.392778 -244.247162)
		(mid 334.20558 -244.297305)
		(end 334.018382 -244.247162)
		(width 0.088646)
		(layer "In6.Cu")
		(net "M_C_CPU0_SB_DQ<2>")
	)
	(arc
		(start 341.537036 -244.247162)
		(mid 341.262837 -244.171327)
		(end 340.986364 -244.238526)
		(width 0.088646)
		(layer "In6.Cu")
		(net "M_C_CPU0_SB_DQ<2>")
	)
	(arc
		(start 343.03843 -243.922804)
		(mid 342.990751 -244.105704)
		(end 342.859868 -244.242082)
		(width 0.088646)
		(layer "In6.Cu")
		(net "M_C_CPU0_SB_DQ<2>")
	)
	(arc
		(start 334.018382 -244.247162)
		(mid 333.73568 -244.171386)
		(end 333.452978 -244.247162)
		(width 0.088646)
		(layer "In6.Cu")
		(net "M_C_CPU0_SB_DQ<2>")
	)
	(arc
		(start 340.971632 -244.247162)
		(mid 340.784434 -244.297305)
		(end 340.597236 -244.247162)
		(width 0.088646)
		(layer "In6.Cu")
		(net "M_C_CPU0_SB_DQ<2>")
	)
	(arc
		(start 341.911432 -244.247162)
		(mid 341.724234 -244.297305)
		(end 341.537036 -244.247162)
		(width 0.088646)
		(layer "In6.Cu")
		(net "M_C_CPU0_SB_DQ<2>")
	)
	(arc
		(start 334.958182 -244.247162)
		(mid 334.67548 -244.171386)
		(end 334.392778 -244.247162)
		(width 0.088646)
		(layer "In6.Cu")
		(net "M_C_CPU0_SB_DQ<2>")
	)
	(arc
		(start 344.385646 -243.76507)
		(mid 344.066337 -243.551714)
		(end 343.689686 -243.47678)
		(width 0.088646)
		(layer "In6.Cu")
		(net "M_C_CPU0_SB_DQ<2>")
	)
	(arc
		(start 336.272632 -244.247162)
		(mid 336.085434 -244.297305)
		(end 335.898236 -244.247162)
		(width 0.088646)
		(layer "In6.Cu")
		(net "M_C_CPU0_SB_DQ<2>")
	)
	(arc
		(start 339.657436 -244.247162)
		(mid 339.383237 -244.171327)
		(end 339.106764 -244.238526)
		(width 0.088646)
		(layer "In6.Cu")
		(net "M_C_CPU0_SB_DQ<2>")
	)
	(arc
		(start 337.212432 -244.247162)
		(mid 337.025234 -244.297305)
		(end 336.838036 -244.247162)
		(width 0.088646)
		(layer "In6.Cu")
		(net "M_C_CPU0_SB_DQ<2>")
	)
	(arc
		(start 335.332578 -244.247162)
		(mid 335.14538 -244.297305)
		(end 334.958182 -244.247162)
		(width 0.088646)
		(layer "In6.Cu")
		(net "M_C_CPU0_SB_DQ<2>")
	)
	(arc
		(start 333.452978 -244.247162)
		(mid 333.26578 -244.297305)
		(end 333.078582 -244.247162)
		(width 0.088646)
		(layer "In6.Cu")
		(net "M_C_CPU0_SB_DQ<2>")
	)
	(arc
		(start 338.152232 -244.247162)
		(mid 337.965034 -244.297305)
		(end 337.777836 -244.247162)
		(width 0.088646)
		(layer "In6.Cu")
		(net "M_C_CPU0_SB_DQ<2>")
	)
	(arc
		(start 340.597236 -244.247162)
		(mid 340.314534 -244.171386)
		(end 340.031832 -244.247162)
		(width 0.088646)
		(layer "In6.Cu")
		(net "M_C_CPU0_SB_DQ<2>")
	)
	(arc
		(start 333.078582 -244.247162)
		(mid 332.843777 -244.173174)
		(end 332.599792 -244.206014)
		(width 0.088646)
		(layer "In6.Cu")
		(net "M_C_CPU0_SB_DQ<2>")
	)
	(arc
		(start 343.65311 -243.47678)
		(mid 343.409926 -243.52517)
		(end 343.203784 -243.662962)
		(width 0.088646)
		(layer "In6.Cu")
		(net "M_C_CPU0_SB_DQ<2>")
	)
	(arc
		(start 337.777836 -244.247162)
		(mid 337.503637 -244.171327)
		(end 337.227164 -244.238526)
		(width 0.088646)
		(layer "In6.Cu")
		(net "M_C_CPU0_SB_DQ<2>")
	)
	(arc
		(start 338.717636 -244.247162)
		(mid 338.434934 -244.171386)
		(end 338.152232 -244.247162)
		(width 0.088646)
		(layer "In6.Cu")
		(net "M_C_CPU0_SB_DQ<2>")
	)
	(segment
		(start 276.469094 -196.041772)
		(end 276.138386 -196.041772)
		(width 0.101854)
		(layer "F.Cu")
		(net "M_C_CPU0_SB_DQ<29>")
	)
	(segment
		(start 278.711914 -196.466714)
		(end 277.072598 -196.466714)
		(width 0.20066)
		(layer "F.Cu")
		(net "M_C_CPU0_SB_DQ<29>")
	)
	(segment
		(start 272.502376 -196.466714)
		(end 271.168114 -196.466714)
		(width 0.20066)
		(layer "F.Cu")
		(net "M_C_CPU0_SB_DQ<29>")
	)
	(segment
		(start 345.01328 -227.36683)
		(end 345.01328 -226.831144)
		(width 0.20066)
		(layer "F.Cu")
		(net "M_C_CPU0_SB_DQ<29>")
	)
	(segment
		(start 276.647656 -196.041772)
		(end 276.469094 -196.041772)
		(width 0.20066)
		(layer "F.Cu")
		(net "M_C_CPU0_SB_DQ<29>")
	)
	(segment
		(start 279.816814 -196.466714)
		(end 278.711914 -196.466714)
		(width 0.20066)
		(layer "F.Cu")
		(net "M_C_CPU0_SB_DQ<29>")
	)
	(segment
		(start 274.152868 -196.041772)
		(end 274.143978 -196.032882)
		(width 0.1016)
		(layer "F.Cu")
		(net "M_C_CPU0_SB_DQ<29>")
	)
	(segment
		(start 276.138386 -196.041772)
		(end 274.152868 -196.041772)
		(width 0.1016)
		(layer "F.Cu")
		(net "M_C_CPU0_SB_DQ<29>")
	)
	(segment
		(start 273.218148 -196.678042)
		(end 272.713704 -196.678042)
		(width 0.20066)
		(layer "F.Cu")
		(net "M_C_CPU0_SB_DQ<29>")
	)
	(segment
		(start 272.713704 -196.678042)
		(end 272.502376 -196.466714)
		(width 0.20066)
		(layer "F.Cu")
		(net "M_C_CPU0_SB_DQ<29>")
	)
	(segment
		(start 345.013534 -227.367084)
		(end 345.01328 -227.36683)
		(width 0.20066)
		(layer "F.Cu")
		(net "M_C_CPU0_SB_DQ<29>")
	)
	(segment
		(start 277.072598 -196.466714)
		(end 276.647656 -196.041772)
		(width 0.20066)
		(layer "F.Cu")
		(net "M_C_CPU0_SB_DQ<29>")
	)
	(segment
		(start 274.143978 -196.032882)
		(end 273.53514 -196.032882)
		(width 0.20066)
		(layer "F.Cu")
		(net "M_C_CPU0_SB_DQ<29>")
	)
	(segment
		(start 273.37258 -196.195442)
		(end 273.37258 -196.52361)
		(width 0.20066)
		(layer "F.Cu")
		(net "M_C_CPU0_SB_DQ<29>")
	)
	(segment
		(start 273.53514 -196.032882)
		(end 273.37258 -196.195442)
		(width 0.20066)
		(layer "F.Cu")
		(net "M_C_CPU0_SB_DQ<29>")
	)
	(segment
		(start 273.37258 -196.52361)
		(end 273.218148 -196.678042)
		(width 0.20066)
		(layer "F.Cu")
		(net "M_C_CPU0_SB_DQ<29>")
	)
	(segment
		(start 338.339684 -224.373948)
		(end 338.339684 -224.389442)
		(width 0.088646)
		(layer "In6.Cu")
		(net "M_C_CPU0_SB_DQ<29>")
	)
	(segment
		(start 341.537036 -224.7138)
		(end 341.528146 -224.70872)
		(width 0.088646)
		(layer "In6.Cu")
		(net "M_C_CPU0_SB_DQ<29>")
	)
	(segment
		(start 287.911794 -193.13271)
		(end 287.375854 -193.202306)
		(width 0.18288)
		(layer "In6.Cu")
		(net "M_C_CPU0_SB_DQ<29>")
	)
	(segment
		(start 337.590384 -224.389442)
		(end 337.590384 -224.379536)
		(width 0.088646)
		(layer "In6.Cu")
		(net "M_C_CPU0_SB_DQ<29>")
	)
	(segment
		(start 338.161122 -224.70872)
		(end 338.152232 -224.7138)
		(width 0.088646)
		(layer "In6.Cu")
		(net "M_C_CPU0_SB_DQ<29>")
	)
	(segment
		(start 342.006682 -225.527616)
		(end 341.997792 -225.522536)
		(width 0.088646)
		(layer "In6.Cu")
		(net "M_C_CPU0_SB_DQ<29>")
	)
	(segment
		(start 341.349584 -224.389442)
		(end 341.349584 -224.379536)
		(width 0.088646)
		(layer "In6.Cu")
		(net "M_C_CPU0_SB_DQ<29>")
	)
	(segment
		(start 340.219284 -224.373948)
		(end 340.219284 -224.389442)
		(width 0.088646)
		(layer "In6.Cu")
		(net "M_C_CPU0_SB_DQ<29>")
	)
	(segment
		(start 306.30241 -193.494152)
		(end 301.60468 -193.13271)
		(width 0.18288)
		(layer "In6.Cu")
		(net "M_C_CPU0_SB_DQ<29>")
	)
	(segment
		(start 339.657436 -224.7138)
		(end 339.648546 -224.70872)
		(width 0.088646)
		(layer "In6.Cu")
		(net "M_C_CPU0_SB_DQ<29>")
	)
	(segment
		(start 322.154042 -209.969354)
		(end 319.251076 -202.961748)
		(width 0.18288)
		(layer "In6.Cu")
		(net "M_C_CPU0_SB_DQ<29>")
	)
	(segment
		(start 307.903372 -193.78549)
		(end 306.30241 -193.494152)
		(width 0.18288)
		(layer "In6.Cu")
		(net "M_C_CPU0_SB_DQ<29>")
	)
	(segment
		(start 342.946482 -225.527616)
		(end 342.93175 -225.51898)
		(width 0.088646)
		(layer "In6.Cu")
		(net "M_C_CPU0_SB_DQ<29>")
	)
	(segment
		(start 336.287364 -223.077278)
		(end 336.272632 -223.085914)
		(width 0.088646)
		(layer "In6.Cu")
		(net "M_C_CPU0_SB_DQ<29>")
	)
	(segment
		(start 285.75889 -193.50355)
		(end 284.19044 -193.972688)
		(width 0.18288)
		(layer "In6.Cu")
		(net "M_C_CPU0_SB_DQ<29>")
	)
	(segment
		(start 309.349394 -194.924172)
		(end 308.375558 -193.950336)
		(width 0.18288)
		(layer "In6.Cu")
		(net "M_C_CPU0_SB_DQ<29>")
	)
	(segment
		(start 335.343246 -223.079818)
		(end 335.332832 -223.085914)
		(width 0.088646)
		(layer "In6.Cu")
		(net "M_C_CPU0_SB_DQ<29>")
	)
	(segment
		(start 331.034136 -219.378022)
		(end 331.034136 -218.849448)
		(width 0.18288)
		(layer "In6.Cu")
		(net "M_C_CPU0_SB_DQ<29>")
	)
	(segment
		(start 314.017152 -198.716392)
		(end 312.384186 -197.083426)
		(width 0.18288)
		(layer "In6.Cu")
		(net "M_C_CPU0_SB_DQ<29>")
	)
	(segment
		(start 283.390848 -194.32778)
		(end 279.816814 -196.466714)
		(width 0.18288)
		(layer "In6.Cu")
		(net "M_C_CPU0_SB_DQ<29>")
	)
	(segment
		(start 340.040722 -224.70872)
		(end 340.031832 -224.7138)
		(width 0.088646)
		(layer "In6.Cu")
		(net "M_C_CPU0_SB_DQ<29>")
	)
	(segment
		(start 301.60468 -193.13271)
		(end 287.911794 -193.13271)
		(width 0.18288)
		(layer "In6.Cu")
		(net "M_C_CPU0_SB_DQ<29>")
	)
	(segment
		(start 344.433652 -226.386136)
		(end 344.356436 -226.341686)
		(width 0.088646)
		(layer "In6.Cu")
		(net "M_C_CPU0_SB_DQ<29>")
	)
	(segment
		(start 337.120484 -223.575626)
		(end 337.120484 -223.561402)
		(width 0.088646)
		(layer "In6.Cu")
		(net "M_C_CPU0_SB_DQ<29>")
	)
	(segment
		(start 343.416636 -226.341686)
		(end 343.407746 -226.336606)
		(width 0.088646)
		(layer "In6.Cu")
		(net "M_C_CPU0_SB_DQ<29>")
	)
	(segment
		(start 311.508394 -197.083426)
		(end 310.619394 -196.194426)
		(width 0.18288)
		(layer "In6.Cu")
		(net "M_C_CPU0_SB_DQ<29>")
	)
	(segment
		(start 331.3684 -219.712286)
		(end 331.034136 -219.378022)
		(width 0.18288)
		(layer "In6.Cu")
		(net "M_C_CPU0_SB_DQ<29>")
	)
	(segment
		(start 343.229184 -226.017328)
		(end 343.229184 -226.003104)
		(width 0.088646)
		(layer "In6.Cu")
		(net "M_C_CPU0_SB_DQ<29>")
	)
	(segment
		(start 309.857394 -196.194426)
		(end 309.349394 -195.686426)
		(width 0.18288)
		(layer "In6.Cu")
		(net "M_C_CPU0_SB_DQ<29>")
	)
	(segment
		(start 315.00572 -198.716392)
		(end 314.017152 -198.716392)
		(width 0.18288)
		(layer "In6.Cu")
		(net "M_C_CPU0_SB_DQ<29>")
	)
	(segment
		(start 331.034136 -218.849448)
		(end 322.154042 -209.969354)
		(width 0.18288)
		(layer "In6.Cu")
		(net "M_C_CPU0_SB_DQ<29>")
	)
	(segment
		(start 284.19044 -193.972688)
		(end 283.390848 -194.32778)
		(width 0.18288)
		(layer "In6.Cu")
		(net "M_C_CPU0_SB_DQ<29>")
	)
	(segment
		(start 308.375558 -193.950336)
		(end 307.903372 -193.78549)
		(width 0.18288)
		(layer "In6.Cu")
		(net "M_C_CPU0_SB_DQ<29>")
	)
	(segment
		(start 341.067136 -223.899984)
		(end 341.056722 -223.893888)
		(width 0.088646)
		(layer "In6.Cu")
		(net "M_C_CPU0_SB_DQ<29>")
	)
	(segment
		(start 339.469984 -224.389442)
		(end 339.469984 -224.379536)
		(width 0.088646)
		(layer "In6.Cu")
		(net "M_C_CPU0_SB_DQ<29>")
	)
	(segment
		(start 319.251076 -202.961748)
		(end 315.00572 -198.716392)
		(width 0.18288)
		(layer "In6.Cu")
		(net "M_C_CPU0_SB_DQ<29>")
	)
	(segment
		(start 334.018636 -223.085914)
		(end 334.008222 -223.079818)
		(width 0.088646)
		(layer "In6.Cu")
		(net "M_C_CPU0_SB_DQ<29>")
	)
	(segment
		(start 339.187536 -223.899984)
		(end 339.177122 -223.893888)
		(width 0.088646)
		(layer "In6.Cu")
		(net "M_C_CPU0_SB_DQ<29>")
	)
	(segment
		(start 332.89113 -221.235016)
		(end 331.3684 -219.712286)
		(width 0.088646)
		(layer "In6.Cu")
		(net "M_C_CPU0_SB_DQ<29>")
	)
	(segment
		(start 312.384186 -197.083426)
		(end 311.508394 -197.083426)
		(width 0.18288)
		(layer "In6.Cu")
		(net "M_C_CPU0_SB_DQ<29>")
	)
	(segment
		(start 287.375854 -193.202306)
		(end 285.75889 -193.50355)
		(width 0.18288)
		(layer "In6.Cu")
		(net "M_C_CPU0_SB_DQ<29>")
	)
	(segment
		(start 337.777836 -224.7138)
		(end 337.768946 -224.70872)
		(width 0.088646)
		(layer "In6.Cu")
		(net "M_C_CPU0_SB_DQ<29>")
	)
	(segment
		(start 336.272632 -223.085914)
		(end 336.26425 -223.09074)
		(width 0.088646)
		(layer "In6.Cu")
		(net "M_C_CPU0_SB_DQ<29>")
	)
	(segment
		(start 309.349394 -195.686426)
		(end 309.349394 -194.924172)
		(width 0.18288)
		(layer "In6.Cu")
		(net "M_C_CPU0_SB_DQ<29>")
	)
	(segment
		(start 337.307936 -223.899984)
		(end 337.299046 -223.894904)
		(width 0.088646)
		(layer "In6.Cu")
		(net "M_C_CPU0_SB_DQ<29>")
	)
	(segment
		(start 341.81923 -225.203258)
		(end 341.81923 -225.187764)
		(width 0.088646)
		(layer "In6.Cu")
		(net "M_C_CPU0_SB_DQ<29>")
	)
	(segment
		(start 310.619394 -196.194426)
		(end 309.857394 -196.194426)
		(width 0.18288)
		(layer "In6.Cu")
		(net "M_C_CPU0_SB_DQ<29>")
	)
	(segment
		(start 332.89113 -222.761556)
		(end 332.89113 -221.235016)
		(width 0.088646)
		(layer "In6.Cu")
		(net "M_C_CPU0_SB_DQ<29>")
	)
	(arc
		(start 338.339684 -224.389442)
		(mid 338.292005 -224.572342)
		(end 338.161122 -224.70872)
		(width 0.088646)
		(layer "In6.Cu")
		(net "M_C_CPU0_SB_DQ<29>")
	)
	(arc
		(start 341.349584 -224.379536)
		(mid 341.271473 -224.102587)
		(end 341.067136 -223.899984)
		(width 0.088646)
		(layer "In6.Cu")
		(net "M_C_CPU0_SB_DQ<29>")
	)
	(arc
		(start 341.528146 -224.70872)
		(mid 341.397232 -224.57236)
		(end 341.349584 -224.389442)
		(width 0.088646)
		(layer "In6.Cu")
		(net "M_C_CPU0_SB_DQ<29>")
	)
	(arc
		(start 341.81923 -225.187764)
		(mid 341.73986 -224.91403)
		(end 341.537036 -224.7138)
		(width 0.088646)
		(layer "In6.Cu")
		(net "M_C_CPU0_SB_DQ<29>")
	)
	(arc
		(start 341.997792 -225.522536)
		(mid 341.866878 -225.386176)
		(end 341.81923 -225.203258)
		(width 0.088646)
		(layer "In6.Cu")
		(net "M_C_CPU0_SB_DQ<29>")
	)
	(arc
		(start 340.501478 -223.899984)
		(mid 340.298655 -224.100215)
		(end 340.219284 -224.373948)
		(width 0.088646)
		(layer "In6.Cu")
		(net "M_C_CPU0_SB_DQ<29>")
	)
	(arc
		(start 340.031832 -224.7138)
		(mid 339.844634 -224.763943)
		(end 339.657436 -224.7138)
		(width 0.088646)
		(layer "In6.Cu")
		(net "M_C_CPU0_SB_DQ<29>")
	)
	(arc
		(start 337.590384 -224.379536)
		(mid 337.512273 -224.102587)
		(end 337.307936 -223.899984)
		(width 0.088646)
		(layer "In6.Cu")
		(net "M_C_CPU0_SB_DQ<29>")
	)
	(arc
		(start 343.791032 -226.341686)
		(mid 343.603834 -226.391829)
		(end 343.416636 -226.341686)
		(width 0.088646)
		(layer "In6.Cu")
		(net "M_C_CPU0_SB_DQ<29>")
	)
	(arc
		(start 334.393032 -223.085914)
		(mid 334.205834 -223.136057)
		(end 334.018636 -223.085914)
		(width 0.088646)
		(layer "In6.Cu")
		(net "M_C_CPU0_SB_DQ<29>")
	)
	(arc
		(start 338.621878 -223.899984)
		(mid 338.419055 -224.100215)
		(end 338.339684 -224.373948)
		(width 0.088646)
		(layer "In6.Cu")
		(net "M_C_CPU0_SB_DQ<29>")
	)
	(arc
		(start 345.01328 -226.831144)
		(mid 344.738044 -226.589651)
		(end 344.433652 -226.386136)
		(width 0.088646)
		(layer "In6.Cu")
		(net "M_C_CPU0_SB_DQ<29>")
	)
	(arc
		(start 344.356436 -226.341686)
		(mid 344.073734 -226.26591)
		(end 343.791032 -226.341686)
		(width 0.088646)
		(layer "In6.Cu")
		(net "M_C_CPU0_SB_DQ<29>")
	)
	(arc
		(start 339.177122 -223.893888)
		(mid 338.89869 -223.824042)
		(end 338.621878 -223.899984)
		(width 0.088646)
		(layer "In6.Cu")
		(net "M_C_CPU0_SB_DQ<29>")
	)
	(arc
		(start 339.648546 -224.70872)
		(mid 339.517632 -224.57236)
		(end 339.469984 -224.389442)
		(width 0.088646)
		(layer "In6.Cu")
		(net "M_C_CPU0_SB_DQ<29>")
	)
	(arc
		(start 342.93175 -225.51898)
		(mid 342.655309 -225.451814)
		(end 342.381078 -225.527616)
		(width 0.088646)
		(layer "In6.Cu")
		(net "M_C_CPU0_SB_DQ<29>")
	)
	(arc
		(start 336.838036 -223.085914)
		(mid 336.563807 -223.009989)
		(end 336.287364 -223.077278)
		(width 0.088646)
		(layer "In6.Cu")
		(net "M_C_CPU0_SB_DQ<29>")
	)
	(arc
		(start 334.958436 -223.085914)
		(mid 334.675734 -223.010172)
		(end 334.393032 -223.085914)
		(width 0.088646)
		(layer "In6.Cu")
		(net "M_C_CPU0_SB_DQ<29>")
	)
	(arc
		(start 338.152232 -224.7138)
		(mid 337.965034 -224.763943)
		(end 337.777836 -224.7138)
		(width 0.088646)
		(layer "In6.Cu")
		(net "M_C_CPU0_SB_DQ<29>")
	)
	(arc
		(start 334.008222 -223.079818)
		(mid 333.72979 -223.010004)
		(end 333.452978 -223.085914)
		(width 0.088646)
		(layer "In6.Cu")
		(net "M_C_CPU0_SB_DQ<29>")
	)
	(arc
		(start 336.26425 -223.09074)
		(mid 336.080742 -223.136018)
		(end 335.89849 -223.085914)
		(width 0.088646)
		(layer "In6.Cu")
		(net "M_C_CPU0_SB_DQ<29>")
	)
	(arc
		(start 337.120484 -223.561402)
		(mid 337.041343 -223.286779)
		(end 336.838036 -223.085914)
		(width 0.088646)
		(layer "In6.Cu")
		(net "M_C_CPU0_SB_DQ<29>")
	)
	(arc
		(start 340.219284 -224.389442)
		(mid 340.171605 -224.572342)
		(end 340.040722 -224.70872)
		(width 0.088646)
		(layer "In6.Cu")
		(net "M_C_CPU0_SB_DQ<29>")
	)
	(arc
		(start 343.407746 -226.336606)
		(mid 343.276832 -226.200246)
		(end 343.229184 -226.017328)
		(width 0.088646)
		(layer "In6.Cu")
		(net "M_C_CPU0_SB_DQ<29>")
	)
	(arc
		(start 335.89849 -223.085914)
		(mid 335.621677 -223.010078)
		(end 335.343246 -223.079818)
		(width 0.088646)
		(layer "In6.Cu")
		(net "M_C_CPU0_SB_DQ<29>")
	)
	(arc
		(start 335.332832 -223.085914)
		(mid 335.145634 -223.136057)
		(end 334.958436 -223.085914)
		(width 0.088646)
		(layer "In6.Cu")
		(net "M_C_CPU0_SB_DQ<29>")
	)
	(arc
		(start 341.056722 -223.893888)
		(mid 340.77829 -223.824042)
		(end 340.501478 -223.899984)
		(width 0.088646)
		(layer "In6.Cu")
		(net "M_C_CPU0_SB_DQ<29>")
	)
	(arc
		(start 342.381078 -225.527616)
		(mid 342.19388 -225.577759)
		(end 342.006682 -225.527616)
		(width 0.088646)
		(layer "In6.Cu")
		(net "M_C_CPU0_SB_DQ<29>")
	)
	(arc
		(start 339.469984 -224.379536)
		(mid 339.391873 -224.102587)
		(end 339.187536 -223.899984)
		(width 0.088646)
		(layer "In6.Cu")
		(net "M_C_CPU0_SB_DQ<29>")
	)
	(arc
		(start 337.299046 -223.894904)
		(mid 337.168132 -223.758544)
		(end 337.120484 -223.575626)
		(width 0.088646)
		(layer "In6.Cu")
		(net "M_C_CPU0_SB_DQ<29>")
	)
	(arc
		(start 337.768946 -224.70872)
		(mid 337.638032 -224.57236)
		(end 337.590384 -224.389442)
		(width 0.088646)
		(layer "In6.Cu")
		(net "M_C_CPU0_SB_DQ<29>")
	)
	(arc
		(start 333.452978 -223.085914)
		(mid 333.078503 -223.085868)
		(end 332.89113 -222.761556)
		(width 0.088646)
		(layer "In6.Cu")
		(net "M_C_CPU0_SB_DQ<29>")
	)
	(arc
		(start 343.229184 -226.003104)
		(mid 343.149965 -225.728419)
		(end 342.946482 -225.527616)
		(width 0.088646)
		(layer "In6.Cu")
		(net "M_C_CPU0_SB_DQ<29>")
	)
	(segment
		(start 273.58213 -197.733666)
		(end 273.37258 -197.943216)
		(width 0.20066)
		(layer "F.Cu")
		(net "M_C_CPU0_SB_DQ<28>")
	)
	(segment
		(start 272.741136 -198.405496)
		(end 272.502376 -198.166736)
		(width 0.20066)
		(layer "F.Cu")
		(net "M_C_CPU0_SB_DQ<28>")
	)
	(segment
		(start 274.40001 -197.741794)
		(end 274.152106 -197.741794)
		(width 0.101854)
		(layer "F.Cu")
		(net "M_C_CPU0_SB_DQ<28>")
	)
	(segment
		(start 273.19986 -198.405496)
		(end 272.741136 -198.405496)
		(width 0.20066)
		(layer "F.Cu")
		(net "M_C_CPU0_SB_DQ<28>")
	)
	(segment
		(start 276.917912 -197.741794)
		(end 276.469094 -197.741794)
		(width 0.20066)
		(layer "F.Cu")
		(net "M_C_CPU0_SB_DQ<28>")
	)
	(segment
		(start 273.37258 -198.232776)
		(end 273.19986 -198.405496)
		(width 0.20066)
		(layer "F.Cu")
		(net "M_C_CPU0_SB_DQ<28>")
	)
	(segment
		(start 276.469094 -197.741794)
		(end 274.40001 -197.741794)
		(width 0.1016)
		(layer "F.Cu")
		(net "M_C_CPU0_SB_DQ<28>")
	)
	(segment
		(start 272.502376 -198.166736)
		(end 271.168114 -198.166736)
		(width 0.20066)
		(layer "F.Cu")
		(net "M_C_CPU0_SB_DQ<28>")
	)
	(segment
		(start 278.711914 -198.166736)
		(end 277.342854 -198.166736)
		(width 0.20066)
		(layer "F.Cu")
		(net "M_C_CPU0_SB_DQ<28>")
	)
	(segment
		(start 274.143978 -197.733666)
		(end 273.58213 -197.733666)
		(width 0.20066)
		(layer "F.Cu")
		(net "M_C_CPU0_SB_DQ<28>")
	)
	(segment
		(start 273.37258 -197.943216)
		(end 273.37258 -198.232776)
		(width 0.20066)
		(layer "F.Cu")
		(net "M_C_CPU0_SB_DQ<28>")
	)
	(segment
		(start 342.194134 -227.367084)
		(end 342.19388 -227.36683)
		(width 0.20066)
		(layer "F.Cu")
		(net "M_C_CPU0_SB_DQ<28>")
	)
	(segment
		(start 277.342854 -198.166736)
		(end 276.917912 -197.741794)
		(width 0.20066)
		(layer "F.Cu")
		(net "M_C_CPU0_SB_DQ<28>")
	)
	(segment
		(start 279.816814 -198.166736)
		(end 278.711914 -198.166736)
		(width 0.20066)
		(layer "F.Cu")
		(net "M_C_CPU0_SB_DQ<28>")
	)
	(segment
		(start 274.152106 -197.741794)
		(end 274.143978 -197.733666)
		(width 0.101854)
		(layer "F.Cu")
		(net "M_C_CPU0_SB_DQ<28>")
	)
	(segment
		(start 342.19388 -227.36683)
		(end 342.19388 -226.831144)
		(width 0.20066)
		(layer "F.Cu")
		(net "M_C_CPU0_SB_DQ<28>")
	)
	(segment
		(start 312.318908 -199.242426)
		(end 311.000394 -199.242426)
		(width 0.18288)
		(layer "In6.Cu")
		(net "M_C_CPU0_SB_DQ<28>")
	)
	(segment
		(start 290.002468 -196.899022)
		(end 289.819588 -196.716142)
		(width 0.18288)
		(layer "In6.Cu")
		(net "M_C_CPU0_SB_DQ<28>")
	)
	(segment
		(start 336.92973 -225.217482)
		(end 336.92973 -225.194622)
		(width 0.088646)
		(layer "In6.Cu")
		(net "M_C_CPU0_SB_DQ<28>")
	)
	(segment
		(start 303.60366 -195.985892)
		(end 302.57877 -194.961002)
		(width 0.18288)
		(layer "In6.Cu")
		(net "M_C_CPU0_SB_DQ<28>")
	)
	(segment
		(start 301.067978 -195.193666)
		(end 294.386254 -195.193666)
		(width 0.18288)
		(layer "In6.Cu")
		(net "M_C_CPU0_SB_DQ<28>")
	)
	(segment
		(start 334.018636 -224.065084)
		(end 334.008222 -224.07118)
		(width 0.088646)
		(layer "In6.Cu")
		(net "M_C_CPU0_SB_DQ<28>")
	)
	(segment
		(start 294.386254 -195.193666)
		(end 293.538148 -196.041772)
		(width 0.18288)
		(layer "In6.Cu")
		(net "M_C_CPU0_SB_DQ<28>")
	)
	(segment
		(start 331.103986 -221.797118)
		(end 330.41971 -221.797118)
		(width 0.088646)
		(layer "In6.Cu")
		(net "M_C_CPU0_SB_DQ<28>")
	)
	(segment
		(start 282.028646 -197.740778)
		(end 281.915362 -197.627494)
		(width 0.18288)
		(layer "In6.Cu")
		(net "M_C_CPU0_SB_DQ<28>")
	)
	(segment
		(start 331.761338 -223.339914)
		(end 331.761338 -222.45447)
		(width 0.088646)
		(layer "In6.Cu")
		(net "M_C_CPU0_SB_DQ<28>")
	)
	(segment
		(start 341.159084 -226.027234)
		(end 341.159084 -226.017328)
		(width 0.088646)
		(layer "In6.Cu")
		(net "M_C_CPU0_SB_DQ<28>")
	)
	(segment
		(start 284.127702 -197.740778)
		(end 282.028646 -197.740778)
		(width 0.18288)
		(layer "In6.Cu")
		(net "M_C_CPU0_SB_DQ<28>")
	)
	(segment
		(start 340.980522 -225.69805)
		(end 340.971632 -225.69297)
		(width 0.088646)
		(layer "In6.Cu")
		(net "M_C_CPU0_SB_DQ<28>")
	)
	(segment
		(start 285.166054 -196.702426)
		(end 284.127702 -197.740778)
		(width 0.18288)
		(layer "In6.Cu")
		(net "M_C_CPU0_SB_DQ<28>")
	)
	(segment
		(start 329.496674 -221.465648)
		(end 329.496674 -219.424504)
		(width 0.18288)
		(layer "In6.Cu")
		(net "M_C_CPU0_SB_DQ<28>")
	)
	(segment
		(start 290.513008 -196.716142)
		(end 290.330128 -196.899022)
		(width 0.18288)
		(layer "In6.Cu")
		(net "M_C_CPU0_SB_DQ<28>")
	)
	(segment
		(start 320.783458 -210.711288)
		(end 317.926212 -203.812648)
		(width 0.18288)
		(layer "In6.Cu")
		(net "M_C_CPU0_SB_DQ<28>")
	)
	(segment
		(start 280.356056 -197.627494)
		(end 279.816814 -198.166736)
		(width 0.18288)
		(layer "In6.Cu")
		(net "M_C_CPU0_SB_DQ<28>")
	)
	(segment
		(start 336.460084 -224.399348)
		(end 336.460084 -224.389442)
		(width 0.088646)
		(layer "In6.Cu")
		(net "M_C_CPU0_SB_DQ<28>")
	)
	(segment
		(start 307.946044 -196.784976)
		(end 307.557678 -196.784976)
		(width 0.18288)
		(layer "In6.Cu")
		(net "M_C_CPU0_SB_DQ<28>")
	)
	(segment
		(start 281.915362 -197.627494)
		(end 280.356056 -197.627494)
		(width 0.18288)
		(layer "In6.Cu")
		(net "M_C_CPU0_SB_DQ<28>")
	)
	(segment
		(start 310.238394 -198.480426)
		(end 309.641494 -198.480426)
		(width 0.18288)
		(layer "In6.Cu")
		(net "M_C_CPU0_SB_DQ<28>")
	)
	(segment
		(start 342.389968 -226.511866)
		(end 342.381078 -226.506786)
		(width 0.088646)
		(layer "In6.Cu")
		(net "M_C_CPU0_SB_DQ<28>")
	)
	(segment
		(start 332.524354 -224.07118)
		(end 332.51394 -224.065084)
		(width 0.088646)
		(layer "In6.Cu")
		(net "M_C_CPU0_SB_DQ<28>")
	)
	(segment
		(start 289.819588 -196.716142)
		(end 289.819588 -196.224652)
		(width 0.18288)
		(layer "In6.Cu")
		(net "M_C_CPU0_SB_DQ<28>")
	)
	(segment
		(start 288.144204 -196.041772)
		(end 287.48355 -196.702426)
		(width 0.18288)
		(layer "In6.Cu")
		(net "M_C_CPU0_SB_DQ<28>")
	)
	(segment
		(start 341.441278 -226.506786)
		(end 341.441532 -226.506786)
		(width 0.088646)
		(layer "In6.Cu")
		(net "M_C_CPU0_SB_DQ<28>")
	)
	(segment
		(start 332.396592 -223.975168)
		(end 331.761338 -223.339914)
		(width 0.088646)
		(layer "In6.Cu")
		(net "M_C_CPU0_SB_DQ<28>")
	)
	(segment
		(start 306.758594 -195.985892)
		(end 303.60366 -195.985892)
		(width 0.18288)
		(layer "In6.Cu")
		(net "M_C_CPU0_SB_DQ<28>")
	)
	(segment
		(start 317.926212 -203.812648)
		(end 314.374022 -200.260458)
		(width 0.18288)
		(layer "In6.Cu")
		(net "M_C_CPU0_SB_DQ<28>")
	)
	(segment
		(start 329.828144 -221.797118)
		(end 329.496674 -221.465648)
		(width 0.18288)
		(layer "In6.Cu")
		(net "M_C_CPU0_SB_DQ<28>")
	)
	(segment
		(start 309.641494 -198.480426)
		(end 307.946044 -196.784976)
		(width 0.18288)
		(layer "In6.Cu")
		(net "M_C_CPU0_SB_DQ<28>")
	)
	(segment
		(start 287.48355 -196.702426)
		(end 285.166054 -196.702426)
		(width 0.18288)
		(layer "In6.Cu")
		(net "M_C_CPU0_SB_DQ<28>")
	)
	(segment
		(start 340.046564 -225.701606)
		(end 340.031832 -225.69297)
		(width 0.088646)
		(layer "In6.Cu")
		(net "M_C_CPU0_SB_DQ<28>")
	)
	(segment
		(start 331.761338 -222.45447)
		(end 331.103986 -221.797118)
		(width 0.088646)
		(layer "In6.Cu")
		(net "M_C_CPU0_SB_DQ<28>")
	)
	(segment
		(start 289.636708 -196.041772)
		(end 288.144204 -196.041772)
		(width 0.18288)
		(layer "In6.Cu")
		(net "M_C_CPU0_SB_DQ<28>")
	)
	(segment
		(start 302.57877 -194.961002)
		(end 301.300642 -194.961002)
		(width 0.18288)
		(layer "In6.Cu")
		(net "M_C_CPU0_SB_DQ<28>")
	)
	(segment
		(start 330.41971 -221.797118)
		(end 329.828144 -221.797118)
		(width 0.18288)
		(layer "In6.Cu")
		(net "M_C_CPU0_SB_DQ<28>")
	)
	(segment
		(start 338.162646 -225.699066)
		(end 338.152232 -225.69297)
		(width 0.088646)
		(layer "In6.Cu")
		(net "M_C_CPU0_SB_DQ<28>")
	)
	(segment
		(start 313.33694 -200.260458)
		(end 312.318908 -199.242426)
		(width 0.18288)
		(layer "In6.Cu")
		(net "M_C_CPU0_SB_DQ<28>")
	)
	(segment
		(start 290.513008 -196.224652)
		(end 290.513008 -196.716142)
		(width 0.18288)
		(layer "In6.Cu")
		(net "M_C_CPU0_SB_DQ<28>")
	)
	(segment
		(start 336.281522 -224.070164)
		(end 336.272632 -224.065084)
		(width 0.088646)
		(layer "In6.Cu")
		(net "M_C_CPU0_SB_DQ<28>")
	)
	(segment
		(start 342.006682 -226.506786)
		(end 341.99195 -226.515422)
		(width 0.088646)
		(layer "In6.Cu")
		(net "M_C_CPU0_SB_DQ<28>")
	)
	(segment
		(start 337.227164 -225.701606)
		(end 337.212432 -225.69297)
		(width 0.088646)
		(layer "In6.Cu")
		(net "M_C_CPU0_SB_DQ<28>")
	)
	(segment
		(start 301.300642 -194.961002)
		(end 301.067978 -195.193666)
		(width 0.18288)
		(layer "In6.Cu")
		(net "M_C_CPU0_SB_DQ<28>")
	)
	(segment
		(start 311.000394 -199.242426)
		(end 310.238394 -198.480426)
		(width 0.18288)
		(layer "In6.Cu")
		(net "M_C_CPU0_SB_DQ<28>")
	)
	(segment
		(start 307.557678 -196.784976)
		(end 306.758594 -195.985892)
		(width 0.18288)
		(layer "In6.Cu")
		(net "M_C_CPU0_SB_DQ<28>")
	)
	(segment
		(start 314.374022 -200.260458)
		(end 313.33694 -200.260458)
		(width 0.18288)
		(layer "In6.Cu")
		(net "M_C_CPU0_SB_DQ<28>")
	)
	(segment
		(start 342.506554 -226.831144)
		(end 342.563958 -226.77374)
		(width 0.088646)
		(layer "In6.Cu")
		(net "M_C_CPU0_SB_DQ<28>")
	)
	(segment
		(start 290.695888 -196.041772)
		(end 290.513008 -196.224652)
		(width 0.18288)
		(layer "In6.Cu")
		(net "M_C_CPU0_SB_DQ<28>")
	)
	(segment
		(start 329.496674 -219.424504)
		(end 320.783458 -210.711288)
		(width 0.18288)
		(layer "In6.Cu")
		(net "M_C_CPU0_SB_DQ<28>")
	)
	(segment
		(start 339.102192 -225.699066)
		(end 339.091778 -225.69297)
		(width 0.088646)
		(layer "In6.Cu")
		(net "M_C_CPU0_SB_DQ<28>")
	)
	(segment
		(start 290.330128 -196.899022)
		(end 290.002468 -196.899022)
		(width 0.18288)
		(layer "In6.Cu")
		(net "M_C_CPU0_SB_DQ<28>")
	)
	(segment
		(start 289.819588 -196.224652)
		(end 289.636708 -196.041772)
		(width 0.18288)
		(layer "In6.Cu")
		(net "M_C_CPU0_SB_DQ<28>")
	)
	(segment
		(start 293.538148 -196.041772)
		(end 290.695888 -196.041772)
		(width 0.18288)
		(layer "In6.Cu")
		(net "M_C_CPU0_SB_DQ<28>")
	)
	(segment
		(start 342.19388 -226.831144)
		(end 342.506554 -226.831144)
		(width 0.088646)
		(layer "In6.Cu")
		(net "M_C_CPU0_SB_DQ<28>")
	)
	(arc
		(start 332.51394 -224.065084)
		(mid 332.452313 -224.02398)
		(end 332.396592 -223.975168)
		(width 0.088646)
		(layer "In6.Cu")
		(net "M_C_CPU0_SB_DQ<28>")
	)
	(arc
		(start 341.99195 -226.515422)
		(mid 341.715475 -226.582742)
		(end 341.441278 -226.506786)
		(width 0.088646)
		(layer "In6.Cu")
		(net "M_C_CPU0_SB_DQ<28>")
	)
	(arc
		(start 333.078582 -224.065084)
		(mid 332.802277 -224.1407)
		(end 332.524354 -224.07118)
		(width 0.088646)
		(layer "In6.Cu")
		(net "M_C_CPU0_SB_DQ<28>")
	)
	(arc
		(start 333.452978 -224.065084)
		(mid 333.26578 -224.014941)
		(end 333.078582 -224.065084)
		(width 0.088646)
		(layer "In6.Cu")
		(net "M_C_CPU0_SB_DQ<28>")
	)
	(arc
		(start 335.898236 -224.065084)
		(mid 335.615534 -224.14086)
		(end 335.332832 -224.065084)
		(width 0.088646)
		(layer "In6.Cu")
		(net "M_C_CPU0_SB_DQ<28>")
	)
	(arc
		(start 334.958436 -224.065084)
		(mid 334.675734 -224.14086)
		(end 334.393032 -224.065084)
		(width 0.088646)
		(layer "In6.Cu")
		(net "M_C_CPU0_SB_DQ<28>")
	)
	(arc
		(start 336.460084 -224.389442)
		(mid 336.412405 -224.206542)
		(end 336.281522 -224.070164)
		(width 0.088646)
		(layer "In6.Cu")
		(net "M_C_CPU0_SB_DQ<28>")
	)
	(arc
		(start 337.777836 -225.69297)
		(mid 337.503607 -225.768895)
		(end 337.227164 -225.701606)
		(width 0.088646)
		(layer "In6.Cu")
		(net "M_C_CPU0_SB_DQ<28>")
	)
	(arc
		(start 337.212432 -225.69297)
		(mid 337.008951 -225.492166)
		(end 336.92973 -225.217482)
		(width 0.088646)
		(layer "In6.Cu")
		(net "M_C_CPU0_SB_DQ<28>")
	)
	(arc
		(start 336.742532 -224.8789)
		(mid 336.538197 -224.676295)
		(end 336.460084 -224.399348)
		(width 0.088646)
		(layer "In6.Cu")
		(net "M_C_CPU0_SB_DQ<28>")
	)
	(arc
		(start 336.272632 -224.065084)
		(mid 336.085434 -224.014941)
		(end 335.898236 -224.065084)
		(width 0.088646)
		(layer "In6.Cu")
		(net "M_C_CPU0_SB_DQ<28>")
	)
	(arc
		(start 336.92973 -225.194622)
		(mid 336.87746 -225.012257)
		(end 336.742532 -224.8789)
		(width 0.088646)
		(layer "In6.Cu")
		(net "M_C_CPU0_SB_DQ<28>")
	)
	(arc
		(start 338.717382 -225.69297)
		(mid 338.440823 -225.768679)
		(end 338.162646 -225.699066)
		(width 0.088646)
		(layer "In6.Cu")
		(net "M_C_CPU0_SB_DQ<28>")
	)
	(arc
		(start 338.152232 -225.69297)
		(mid 337.965034 -225.642827)
		(end 337.777836 -225.69297)
		(width 0.088646)
		(layer "In6.Cu")
		(net "M_C_CPU0_SB_DQ<28>")
	)
	(arc
		(start 342.381078 -226.506786)
		(mid 342.19388 -226.456643)
		(end 342.006682 -226.506786)
		(width 0.088646)
		(layer "In6.Cu")
		(net "M_C_CPU0_SB_DQ<28>")
	)
	(arc
		(start 334.008222 -224.07118)
		(mid 333.72979 -224.141026)
		(end 333.452978 -224.065084)
		(width 0.088646)
		(layer "In6.Cu")
		(net "M_C_CPU0_SB_DQ<28>")
	)
	(arc
		(start 339.091778 -225.69297)
		(mid 338.90458 -225.642827)
		(end 338.717382 -225.69297)
		(width 0.088646)
		(layer "In6.Cu")
		(net "M_C_CPU0_SB_DQ<28>")
	)
	(arc
		(start 340.971632 -225.69297)
		(mid 340.784434 -225.642827)
		(end 340.597236 -225.69297)
		(width 0.088646)
		(layer "In6.Cu")
		(net "M_C_CPU0_SB_DQ<28>")
	)
	(arc
		(start 340.031832 -225.69297)
		(mid 339.844634 -225.642827)
		(end 339.657436 -225.69297)
		(width 0.088646)
		(layer "In6.Cu")
		(net "M_C_CPU0_SB_DQ<28>")
	)
	(arc
		(start 339.657436 -225.69297)
		(mid 339.380623 -225.768806)
		(end 339.102192 -225.699066)
		(width 0.088646)
		(layer "In6.Cu")
		(net "M_C_CPU0_SB_DQ<28>")
	)
	(arc
		(start 341.159084 -226.017328)
		(mid 341.111405 -225.834428)
		(end 340.980522 -225.69805)
		(width 0.088646)
		(layer "In6.Cu")
		(net "M_C_CPU0_SB_DQ<28>")
	)
	(arc
		(start 340.597236 -225.69297)
		(mid 340.323007 -225.768895)
		(end 340.046564 -225.701606)
		(width 0.088646)
		(layer "In6.Cu")
		(net "M_C_CPU0_SB_DQ<28>")
	)
	(arc
		(start 335.332832 -224.065084)
		(mid 335.145634 -224.014941)
		(end 334.958436 -224.065084)
		(width 0.088646)
		(layer "In6.Cu")
		(net "M_C_CPU0_SB_DQ<28>")
	)
	(arc
		(start 341.441532 -226.506786)
		(mid 341.237197 -226.304181)
		(end 341.159084 -226.027234)
		(width 0.088646)
		(layer "In6.Cu")
		(net "M_C_CPU0_SB_DQ<28>")
	)
	(arc
		(start 342.563958 -226.77374)
		(mid 342.505802 -226.623627)
		(end 342.389968 -226.511866)
		(width 0.088646)
		(layer "In6.Cu")
		(net "M_C_CPU0_SB_DQ<28>")
	)
	(arc
		(start 334.393032 -224.065084)
		(mid 334.205834 -224.014941)
		(end 334.018636 -224.065084)
		(width 0.088646)
		(layer "In6.Cu")
		(net "M_C_CPU0_SB_DQ<28>")
	)
	(segment
		(start 277.091394 -201.863452)
		(end 277.091394 -201.692764)
		(width 0.20066)
		(layer "F.Cu")
		(net "M_C_CPU0_SB_DQ<27>")
	)
	(segment
		(start 281.129994 -201.562462)
		(end 280.73477 -201.562462)
		(width 0.20066)
		(layer "F.Cu")
		(net "M_C_CPU0_SB_DQ<27>")
	)
	(segment
		(start 281.34183 -201.774298)
		(end 281.129994 -201.562462)
		(width 0.20066)
		(layer "F.Cu")
		(net "M_C_CPU0_SB_DQ<27>")
	)
	(segment
		(start 277.839932 -201.991722)
		(end 277.601934 -201.991722)
		(width 0.101854)
		(layer "F.Cu")
		(net "M_C_CPU0_SB_DQ<27>")
	)
	(segment
		(start 277.58771 -202.005946)
		(end 277.233888 -202.005946)
		(width 0.20066)
		(layer "F.Cu")
		(net "M_C_CPU0_SB_DQ<27>")
	)
	(segment
		(start 279.912826 -201.991722)
		(end 277.839932 -201.991722)
		(width 0.1016)
		(layer "F.Cu")
		(net "M_C_CPU0_SB_DQ<27>")
	)
	(segment
		(start 280.73477 -201.562462)
		(end 280.606246 -201.690986)
		(width 0.20066)
		(layer "F.Cu")
		(net "M_C_CPU0_SB_DQ<27>")
	)
	(segment
		(start 280.606246 -201.690986)
		(end 280.606246 -201.842624)
		(width 0.20066)
		(layer "F.Cu")
		(net "M_C_CPU0_SB_DQ<27>")
	)
	(segment
		(start 281.99588 -201.56678)
		(end 281.788362 -201.774298)
		(width 0.20066)
		(layer "F.Cu")
		(net "M_C_CPU0_SB_DQ<27>")
	)
	(segment
		(start 277.601934 -201.991722)
		(end 277.58771 -202.005946)
		(width 0.101854)
		(layer "F.Cu")
		(net "M_C_CPU0_SB_DQ<27>")
	)
	(segment
		(start 280.606246 -201.842624)
		(end 280.457148 -201.991722)
		(width 0.20066)
		(layer "F.Cu")
		(net "M_C_CPU0_SB_DQ<27>")
	)
	(segment
		(start 283.916882 -201.56678)
		(end 282.811982 -201.56678)
		(width 0.20066)
		(layer "F.Cu")
		(net "M_C_CPU0_SB_DQ<27>")
	)
	(segment
		(start 277.233888 -202.005946)
		(end 277.091394 -201.863452)
		(width 0.20066)
		(layer "F.Cu")
		(net "M_C_CPU0_SB_DQ<27>")
	)
	(segment
		(start 281.788362 -201.774298)
		(end 281.34183 -201.774298)
		(width 0.20066)
		(layer "F.Cu")
		(net "M_C_CPU0_SB_DQ<27>")
	)
	(segment
		(start 345.013534 -228.99497)
		(end 345.01328 -228.994716)
		(width 0.20066)
		(layer "F.Cu")
		(net "M_C_CPU0_SB_DQ<27>")
	)
	(segment
		(start 280.457148 -201.991722)
		(end 279.912826 -201.991722)
		(width 0.20066)
		(layer "F.Cu")
		(net "M_C_CPU0_SB_DQ<27>")
	)
	(segment
		(start 277.091394 -201.692764)
		(end 276.96541 -201.56678)
		(width 0.20066)
		(layer "F.Cu")
		(net "M_C_CPU0_SB_DQ<27>")
	)
	(segment
		(start 282.811982 -201.56678)
		(end 281.99588 -201.56678)
		(width 0.20066)
		(layer "F.Cu")
		(net "M_C_CPU0_SB_DQ<27>")
	)
	(segment
		(start 345.01328 -228.994716)
		(end 345.01328 -228.45903)
		(width 0.20066)
		(layer "F.Cu")
		(net "M_C_CPU0_SB_DQ<27>")
	)
	(segment
		(start 276.96541 -201.56678)
		(end 275.268182 -201.56678)
		(width 0.20066)
		(layer "F.Cu")
		(net "M_C_CPU0_SB_DQ<27>")
	)
	(segment
		(start 291.774118 -199.689212)
		(end 291.614098 -199.849232)
		(width 0.18288)
		(layer "In6.Cu")
		(net "M_C_CPU0_SB_DQ<27>")
	)
	(segment
		(start 330.809854 -224.069656)
		(end 330.657962 -223.917764)
		(width 0.088646)
		(layer "In6.Cu")
		(net "M_C_CPU0_SB_DQ<27>")
	)
	(segment
		(start 293.000938 -200.073006)
		(end 292.840918 -200.233026)
		(width 0.18288)
		(layer "In6.Cu")
		(net "M_C_CPU0_SB_DQ<27>")
	)
	(segment
		(start 342.946736 -228.134672)
		(end 342.946482 -228.134672)
		(width 0.088646)
		(layer "In6.Cu")
		(net "M_C_CPU0_SB_DQ<27>")
	)
	(segment
		(start 343.321132 -228.134926)
		(end 343.320878 -228.134672)
		(width 0.088646)
		(layer "In6.Cu")
		(net "M_C_CPU0_SB_DQ<27>")
	)
	(segment
		(start 294.051228 -200.233026)
		(end 293.854378 -200.233026)
		(width 0.18288)
		(layer "In6.Cu")
		(net "M_C_CPU0_SB_DQ<27>")
	)
	(segment
		(start 334.403446 -226.33559)
		(end 334.393032 -226.341686)
		(width 0.088646)
		(layer "In6.Cu")
		(net "M_C_CPU0_SB_DQ<27>")
	)
	(segment
		(start 291.614098 -199.849232)
		(end 291.614098 -200.073006)
		(width 0.18288)
		(layer "In6.Cu")
		(net "M_C_CPU0_SB_DQ<27>")
	)
	(segment
		(start 344.28938 -228.766878)
		(end 344.260932 -228.783388)
		(width 0.088646)
		(layer "In6.Cu")
		(net "M_C_CPU0_SB_DQ<27>")
	)
	(segment
		(start 343.886536 -228.783388)
		(end 343.600278 -228.618034)
		(width 0.088646)
		(layer "In6.Cu")
		(net "M_C_CPU0_SB_DQ<27>")
	)
	(segment
		(start 297.455082 -199.53859)
		(end 297.455082 -200.10882)
		(width 0.18288)
		(layer "In6.Cu")
		(net "M_C_CPU0_SB_DQ<27>")
	)
	(segment
		(start 338.166964 -227.960682)
		(end 338.152232 -227.969318)
		(width 0.088646)
		(layer "In6.Cu")
		(net "M_C_CPU0_SB_DQ<27>")
	)
	(segment
		(start 335.428336 -227.155502)
		(end 335.419446 -227.150422)
		(width 0.088646)
		(layer "In6.Cu")
		(net "M_C_CPU0_SB_DQ<27>")
	)
	(segment
		(start 303.888394 -201.185526)
		(end 302.994568 -200.2917)
		(width 0.18288)
		(layer "In6.Cu")
		(net "M_C_CPU0_SB_DQ<27>")
	)
	(segment
		(start 294.211248 -200.393046)
		(end 294.051228 -200.233026)
		(width 0.18288)
		(layer "In6.Cu")
		(net "M_C_CPU0_SB_DQ<27>")
	)
	(segment
		(start 299.908722 -199.836278)
		(end 299.908722 -200.10882)
		(width 0.18288)
		(layer "In6.Cu")
		(net "M_C_CPU0_SB_DQ<27>")
	)
	(segment
		(start 330.809854 -224.288858)
		(end 330.809854 -224.069656)
		(width 0.088646)
		(layer "In6.Cu")
		(net "M_C_CPU0_SB_DQ<27>")
	)
	(segment
		(start 309.657242 -202.265026)
		(end 308.35219 -200.959974)
		(width 0.18288)
		(layer "In6.Cu")
		(net "M_C_CPU0_SB_DQ<27>")
	)
	(segment
		(start 327.34123 -220.293184)
		(end 318.75222 -211.704174)
		(width 0.18288)
		(layer "In6.Cu")
		(net "M_C_CPU0_SB_DQ<27>")
	)
	(segment
		(start 293.160958 -199.689212)
		(end 293.000938 -199.849232)
		(width 0.18288)
		(layer "In6.Cu")
		(net "M_C_CPU0_SB_DQ<27>")
	)
	(segment
		(start 307.012594 -201.185526)
		(end 305.989482 -201.185526)
		(width 0.18288)
		(layer "In6.Cu")
		(net "M_C_CPU0_SB_DQ<27>")
	)
	(segment
		(start 332.515972 -226.265994)
		(end 332.255114 -226.005136)
		(width 0.088646)
		(layer "In6.Cu")
		(net "M_C_CPU0_SB_DQ<27>")
	)
	(segment
		(start 342.006682 -228.783388)
		(end 341.99195 -228.774752)
		(width 0.088646)
		(layer "In6.Cu")
		(net "M_C_CPU0_SB_DQ<27>")
	)
	(segment
		(start 294.211248 -200.640696)
		(end 294.211248 -200.393046)
		(width 0.18288)
		(layer "In6.Cu")
		(net "M_C_CPU0_SB_DQ<27>")
	)
	(segment
		(start 332.255114 -226.005136)
		(end 332.255114 -225.734118)
		(width 0.088646)
		(layer "In6.Cu")
		(net "M_C_CPU0_SB_DQ<27>")
	)
	(segment
		(start 327.34123 -223.186752)
		(end 327.34123 -220.293184)
		(width 0.18288)
		(layer "In6.Cu")
		(net "M_C_CPU0_SB_DQ<27>")
	)
	(segment
		(start 299.908722 -200.10882)
		(end 299.725842 -200.2917)
		(width 0.18288)
		(layer "In6.Cu")
		(net "M_C_CPU0_SB_DQ<27>")
	)
	(segment
		(start 298.148502 -200.10882)
		(end 298.148502 -199.53859)
		(width 0.18288)
		(layer "In6.Cu")
		(net "M_C_CPU0_SB_DQ<27>")
	)
	(segment
		(start 345.01328 -228.45903)
		(end 344.28938 -228.766878)
		(width 0.088646)
		(layer "In6.Cu")
		(net "M_C_CPU0_SB_DQ<27>")
	)
	(segment
		(start 337.227164 -227.960682)
		(end 337.212432 -227.969318)
		(width 0.088646)
		(layer "In6.Cu")
		(net "M_C_CPU0_SB_DQ<27>")
	)
	(segment
		(start 293.694358 -199.849232)
		(end 293.534338 -199.689212)
		(width 0.18288)
		(layer "In6.Cu")
		(net "M_C_CPU0_SB_DQ<27>")
	)
	(segment
		(start 328.072242 -223.917764)
		(end 327.34123 -223.186752)
		(width 0.18288)
		(layer "In6.Cu")
		(net "M_C_CPU0_SB_DQ<27>")
	)
	(segment
		(start 297.455082 -200.10882)
		(end 297.272202 -200.2917)
		(width 0.18288)
		(layer "In6.Cu")
		(net "M_C_CPU0_SB_DQ<27>")
	)
	(segment
		(start 305.115722 -201.002646)
		(end 304.932842 -201.185526)
		(width 0.18288)
		(layer "In6.Cu")
		(net "M_C_CPU0_SB_DQ<27>")
	)
	(segment
		(start 300.419262 -199.653398)
		(end 300.091602 -199.653398)
		(width 0.18288)
		(layer "In6.Cu")
		(net "M_C_CPU0_SB_DQ<27>")
	)
	(segment
		(start 311.457594 -203.090526)
		(end 310.632094 -202.265026)
		(width 0.18288)
		(layer "In6.Cu")
		(net "M_C_CPU0_SB_DQ<27>")
	)
	(segment
		(start 294.71239 -201.141838)
		(end 294.211248 -200.640696)
		(width 0.18288)
		(layer "In6.Cu")
		(net "M_C_CPU0_SB_DQ<27>")
	)
	(segment
		(start 339.657182 -227.969318)
		(end 339.646768 -227.963222)
		(width 0.088646)
		(layer "In6.Cu")
		(net "M_C_CPU0_SB_DQ<27>")
	)
	(segment
		(start 298.148502 -199.53859)
		(end 297.965622 -199.35571)
		(width 0.18288)
		(layer "In6.Cu")
		(net "M_C_CPU0_SB_DQ<27>")
	)
	(segment
		(start 336.287364 -227.960682)
		(end 336.272632 -227.969318)
		(width 0.088646)
		(layer "In6.Cu")
		(net "M_C_CPU0_SB_DQ<27>")
	)
	(segment
		(start 295.24706 -201.141838)
		(end 294.71239 -201.141838)
		(width 0.18288)
		(layer "In6.Cu")
		(net "M_C_CPU0_SB_DQ<27>")
	)
	(segment
		(start 297.637962 -199.35571)
		(end 297.455082 -199.53859)
		(width 0.18288)
		(layer "In6.Cu")
		(net "M_C_CPU0_SB_DQ<27>")
	)
	(segment
		(start 332.79588 -226.265994)
		(end 332.515972 -226.265994)
		(width 0.088646)
		(layer "In6.Cu")
		(net "M_C_CPU0_SB_DQ<27>")
	)
	(segment
		(start 305.989482 -201.185526)
		(end 305.806602 -201.002646)
		(width 0.18288)
		(layer "In6.Cu")
		(net "M_C_CPU0_SB_DQ<27>")
	)
	(segment
		(start 302.994568 -200.2917)
		(end 300.785022 -200.2917)
		(width 0.18288)
		(layer "In6.Cu")
		(net "M_C_CPU0_SB_DQ<27>")
	)
	(segment
		(start 293.694358 -200.073006)
		(end 293.694358 -199.849232)
		(width 0.18288)
		(layer "In6.Cu")
		(net "M_C_CPU0_SB_DQ<27>")
	)
	(segment
		(start 285.842202 -200.233026)
		(end 284.508448 -201.56678)
		(width 0.18288)
		(layer "In6.Cu")
		(net "M_C_CPU0_SB_DQ<27>")
	)
	(segment
		(start 293.854378 -200.233026)
		(end 293.694358 -200.073006)
		(width 0.18288)
		(layer "In6.Cu")
		(net "M_C_CPU0_SB_DQ<27>")
	)
	(segment
		(start 292.307518 -200.073006)
		(end 292.307518 -199.849232)
		(width 0.18288)
		(layer "In6.Cu")
		(net "M_C_CPU0_SB_DQ<27>")
	)
	(segment
		(start 298.331382 -200.2917)
		(end 298.148502 -200.10882)
		(width 0.18288)
		(layer "In6.Cu")
		(net "M_C_CPU0_SB_DQ<27>")
	)
	(segment
		(start 335.434432 -227.159058)
		(end 335.428336 -227.155502)
		(width 0.088646)
		(layer "In6.Cu")
		(net "M_C_CPU0_SB_DQ<27>")
	)
	(segment
		(start 291.454078 -200.233026)
		(end 285.842202 -200.233026)
		(width 0.18288)
		(layer "In6.Cu")
		(net "M_C_CPU0_SB_DQ<27>")
	)
	(segment
		(start 305.806602 -200.52792)
		(end 305.623722 -200.34504)
		(width 0.18288)
		(layer "In6.Cu")
		(net "M_C_CPU0_SB_DQ<27>")
	)
	(segment
		(start 314.503816 -204.672184)
		(end 313.979052 -204.672184)
		(width 0.18288)
		(layer "In6.Cu")
		(net "M_C_CPU0_SB_DQ<27>")
	)
	(segment
		(start 305.115722 -200.52792)
		(end 305.115722 -201.002646)
		(width 0.18288)
		(layer "In6.Cu")
		(net "M_C_CPU0_SB_DQ<27>")
	)
	(segment
		(start 292.307518 -199.849232)
		(end 292.147498 -199.689212)
		(width 0.18288)
		(layer "In6.Cu")
		(net "M_C_CPU0_SB_DQ<27>")
	)
	(segment
		(start 291.614098 -200.073006)
		(end 291.454078 -200.233026)
		(width 0.18288)
		(layer "In6.Cu")
		(net "M_C_CPU0_SB_DQ<27>")
	)
	(segment
		(start 342.946482 -228.134672)
		(end 342.660732 -228.299772)
		(width 0.088646)
		(layer "In6.Cu")
		(net "M_C_CPU0_SB_DQ<27>")
	)
	(segment
		(start 318.75222 -211.704174)
		(end 316.78372 -206.952088)
		(width 0.18288)
		(layer "In6.Cu")
		(net "M_C_CPU0_SB_DQ<27>")
	)
	(segment
		(start 334.970374 -226.348798)
		(end 334.958182 -226.341686)
		(width 0.088646)
		(layer "In6.Cu")
		(net "M_C_CPU0_SB_DQ<27>")
	)
	(segment
		(start 335.898236 -227.969318)
		(end 335.889346 -227.964238)
		(width 0.088646)
		(layer "In6.Cu")
		(net "M_C_CPU0_SB_DQ<27>")
	)
	(segment
		(start 341.066882 -228.783388)
		(end 341.05215 -228.774752)
		(width 0.088646)
		(layer "In6.Cu")
		(net "M_C_CPU0_SB_DQ<27>")
	)
	(segment
		(start 330.657962 -223.917764)
		(end 330.41971 -223.917764)
		(width 0.088646)
		(layer "In6.Cu")
		(net "M_C_CPU0_SB_DQ<27>")
	)
	(segment
		(start 308.35219 -200.959974)
		(end 307.238146 -200.959974)
		(width 0.18288)
		(layer "In6.Cu")
		(net "M_C_CPU0_SB_DQ<27>")
	)
	(segment
		(start 305.623722 -200.34504)
		(end 305.298602 -200.34504)
		(width 0.18288)
		(layer "In6.Cu")
		(net "M_C_CPU0_SB_DQ<27>")
	)
	(segment
		(start 330.41971 -223.917764)
		(end 328.072242 -223.917764)
		(width 0.18288)
		(layer "In6.Cu")
		(net "M_C_CPU0_SB_DQ<27>")
	)
	(segment
		(start 284.508448 -201.56678)
		(end 283.916882 -201.56678)
		(width 0.18288)
		(layer "In6.Cu")
		(net "M_C_CPU0_SB_DQ<27>")
	)
	(segment
		(start 300.091602 -199.653398)
		(end 299.908722 -199.836278)
		(width 0.18288)
		(layer "In6.Cu")
		(net "M_C_CPU0_SB_DQ<27>")
	)
	(segment
		(start 300.785022 -200.2917)
		(end 300.602142 -200.10882)
		(width 0.18288)
		(layer "In6.Cu")
		(net "M_C_CPU0_SB_DQ<27>")
	)
	(segment
		(start 293.534338 -199.689212)
		(end 293.160958 -199.689212)
		(width 0.18288)
		(layer "In6.Cu")
		(net "M_C_CPU0_SB_DQ<27>")
	)
	(segment
		(start 305.298602 -200.34504)
		(end 305.115722 -200.52792)
		(width 0.18288)
		(layer "In6.Cu")
		(net "M_C_CPU0_SB_DQ<27>")
	)
	(segment
		(start 293.000938 -199.849232)
		(end 293.000938 -200.073006)
		(width 0.18288)
		(layer "In6.Cu")
		(net "M_C_CPU0_SB_DQ<27>")
	)
	(segment
		(start 304.932842 -201.185526)
		(end 303.888394 -201.185526)
		(width 0.18288)
		(layer "In6.Cu")
		(net "M_C_CPU0_SB_DQ<27>")
	)
	(segment
		(start 292.147498 -199.689212)
		(end 291.774118 -199.689212)
		(width 0.18288)
		(layer "In6.Cu")
		(net "M_C_CPU0_SB_DQ<27>")
	)
	(segment
		(start 297.272202 -200.2917)
		(end 296.097198 -200.2917)
		(width 0.18288)
		(layer "In6.Cu")
		(net "M_C_CPU0_SB_DQ<27>")
	)
	(segment
		(start 316.78372 -206.952088)
		(end 314.503816 -204.672184)
		(width 0.18288)
		(layer "In6.Cu")
		(net "M_C_CPU0_SB_DQ<27>")
	)
	(segment
		(start 297.965622 -199.35571)
		(end 297.637962 -199.35571)
		(width 0.18288)
		(layer "In6.Cu")
		(net "M_C_CPU0_SB_DQ<27>")
	)
	(segment
		(start 339.939884 -228.467666)
		(end 339.939884 -228.444806)
		(width 0.088646)
		(layer "In6.Cu")
		(net "M_C_CPU0_SB_DQ<27>")
	)
	(segment
		(start 334.018636 -226.341686)
		(end 334.008222 -226.33559)
		(width 0.088646)
		(layer "In6.Cu")
		(net "M_C_CPU0_SB_DQ<27>")
	)
	(segment
		(start 332.255114 -225.734118)
		(end 330.809854 -224.288858)
		(width 0.088646)
		(layer "In6.Cu")
		(net "M_C_CPU0_SB_DQ<27>")
	)
	(segment
		(start 310.632094 -202.265026)
		(end 309.657242 -202.265026)
		(width 0.18288)
		(layer "In6.Cu")
		(net "M_C_CPU0_SB_DQ<27>")
	)
	(segment
		(start 307.238146 -200.959974)
		(end 307.012594 -201.185526)
		(width 0.18288)
		(layer "In6.Cu")
		(net "M_C_CPU0_SB_DQ<27>")
	)
	(segment
		(start 312.397394 -203.090526)
		(end 311.457594 -203.090526)
		(width 0.18288)
		(layer "In6.Cu")
		(net "M_C_CPU0_SB_DQ<27>")
	)
	(segment
		(start 305.806602 -201.002646)
		(end 305.806602 -200.52792)
		(width 0.18288)
		(layer "In6.Cu")
		(net "M_C_CPU0_SB_DQ<27>")
	)
	(segment
		(start 342.381332 -228.783134)
		(end 342.381078 -228.783388)
		(width 0.088646)
		(layer "In6.Cu")
		(net "M_C_CPU0_SB_DQ<27>")
	)
	(segment
		(start 296.097198 -200.2917)
		(end 295.24706 -201.141838)
		(width 0.18288)
		(layer "In6.Cu")
		(net "M_C_CPU0_SB_DQ<27>")
	)
	(segment
		(start 292.467538 -200.233026)
		(end 292.307518 -200.073006)
		(width 0.18288)
		(layer "In6.Cu")
		(net "M_C_CPU0_SB_DQ<27>")
	)
	(segment
		(start 292.840918 -200.233026)
		(end 292.467538 -200.233026)
		(width 0.18288)
		(layer "In6.Cu")
		(net "M_C_CPU0_SB_DQ<27>")
	)
	(segment
		(start 300.602142 -200.10882)
		(end 300.602142 -199.836278)
		(width 0.18288)
		(layer "In6.Cu")
		(net "M_C_CPU0_SB_DQ<27>")
	)
	(segment
		(start 299.725842 -200.2917)
		(end 298.331382 -200.2917)
		(width 0.18288)
		(layer "In6.Cu")
		(net "M_C_CPU0_SB_DQ<27>")
	)
	(segment
		(start 300.602142 -199.836278)
		(end 300.419262 -199.653398)
		(width 0.18288)
		(layer "In6.Cu")
		(net "M_C_CPU0_SB_DQ<27>")
	)
	(segment
		(start 313.979052 -204.672184)
		(end 312.397394 -203.090526)
		(width 0.18288)
		(layer "In6.Cu")
		(net "M_C_CPU0_SB_DQ<27>")
	)
	(arc
		(start 336.272632 -227.969318)
		(mid 336.085434 -228.019461)
		(end 335.898236 -227.969318)
		(width 0.088646)
		(layer "In6.Cu")
		(net "M_C_CPU0_SB_DQ<27>")
	)
	(arc
		(start 341.441278 -228.783388)
		(mid 341.25408 -228.833531)
		(end 341.066882 -228.783388)
		(width 0.088646)
		(layer "In6.Cu")
		(net "M_C_CPU0_SB_DQ<27>")
	)
	(arc
		(start 335.710784 -227.64496)
		(mid 335.636868 -227.365458)
		(end 335.434432 -227.159058)
		(width 0.088646)
		(layer "In6.Cu")
		(net "M_C_CPU0_SB_DQ<27>")
	)
	(arc
		(start 339.939884 -228.444806)
		(mid 339.860665 -228.170121)
		(end 339.657182 -227.969318)
		(width 0.088646)
		(layer "In6.Cu")
		(net "M_C_CPU0_SB_DQ<27>")
	)
	(arc
		(start 335.889346 -227.964238)
		(mid 335.758432 -227.827878)
		(end 335.710784 -227.64496)
		(width 0.088646)
		(layer "In6.Cu")
		(net "M_C_CPU0_SB_DQ<27>")
	)
	(arc
		(start 337.777836 -227.969318)
		(mid 337.503607 -227.893393)
		(end 337.227164 -227.960682)
		(width 0.088646)
		(layer "In6.Cu")
		(net "M_C_CPU0_SB_DQ<27>")
	)
	(arc
		(start 339.646768 -227.963222)
		(mid 339.36859 -227.89353)
		(end 339.092032 -227.969318)
		(width 0.088646)
		(layer "In6.Cu")
		(net "M_C_CPU0_SB_DQ<27>")
	)
	(arc
		(start 335.419446 -227.150422)
		(mid 335.288532 -227.014062)
		(end 335.240884 -226.831144)
		(width 0.088646)
		(layer "In6.Cu")
		(net "M_C_CPU0_SB_DQ<27>")
	)
	(arc
		(start 341.05215 -228.774752)
		(mid 340.775675 -228.707432)
		(end 340.501478 -228.783388)
		(width 0.088646)
		(layer "In6.Cu")
		(net "M_C_CPU0_SB_DQ<27>")
	)
	(arc
		(start 343.600278 -228.618034)
		(mid 343.532948 -228.550876)
		(end 343.50833 -228.45903)
		(width 0.088646)
		(layer "In6.Cu")
		(net "M_C_CPU0_SB_DQ<27>")
	)
	(arc
		(start 336.838036 -227.969318)
		(mid 336.563807 -227.893393)
		(end 336.287364 -227.960682)
		(width 0.088646)
		(layer "In6.Cu")
		(net "M_C_CPU0_SB_DQ<27>")
	)
	(arc
		(start 343.320878 -228.134672)
		(mid 343.133824 -228.084622)
		(end 342.946736 -228.134672)
		(width 0.088646)
		(layer "In6.Cu")
		(net "M_C_CPU0_SB_DQ<27>")
	)
	(arc
		(start 342.381078 -228.783388)
		(mid 342.19388 -228.833531)
		(end 342.006682 -228.783388)
		(width 0.088646)
		(layer "In6.Cu")
		(net "M_C_CPU0_SB_DQ<27>")
	)
	(arc
		(start 338.717636 -227.969318)
		(mid 338.443407 -227.893393)
		(end 338.166964 -227.960682)
		(width 0.088646)
		(layer "In6.Cu")
		(net "M_C_CPU0_SB_DQ<27>")
	)
	(arc
		(start 340.501478 -228.783388)
		(mid 340.31428 -228.833531)
		(end 340.127082 -228.783388)
		(width 0.088646)
		(layer "In6.Cu")
		(net "M_C_CPU0_SB_DQ<27>")
	)
	(arc
		(start 334.958182 -226.341686)
		(mid 334.681623 -226.265943)
		(end 334.403446 -226.33559)
		(width 0.088646)
		(layer "In6.Cu")
		(net "M_C_CPU0_SB_DQ<27>")
	)
	(arc
		(start 333.452978 -226.341686)
		(mid 333.26578 -226.391829)
		(end 333.078582 -226.341686)
		(width 0.088646)
		(layer "In6.Cu")
		(net "M_C_CPU0_SB_DQ<27>")
	)
	(arc
		(start 344.260932 -228.783388)
		(mid 344.073734 -228.833565)
		(end 343.886536 -228.783388)
		(width 0.088646)
		(layer "In6.Cu")
		(net "M_C_CPU0_SB_DQ<27>")
	)
	(arc
		(start 335.240884 -226.831144)
		(mid 335.168649 -226.55462)
		(end 334.970374 -226.348798)
		(width 0.088646)
		(layer "In6.Cu")
		(net "M_C_CPU0_SB_DQ<27>")
	)
	(arc
		(start 342.56853 -228.45903)
		(mid 342.518366 -228.646168)
		(end 342.381332 -228.783134)
		(width 0.088646)
		(layer "In6.Cu")
		(net "M_C_CPU0_SB_DQ<27>")
	)
	(arc
		(start 338.152232 -227.969318)
		(mid 337.965034 -228.019461)
		(end 337.777836 -227.969318)
		(width 0.088646)
		(layer "In6.Cu")
		(net "M_C_CPU0_SB_DQ<27>")
	)
	(arc
		(start 334.393032 -226.341686)
		(mid 334.205834 -226.391829)
		(end 334.018636 -226.341686)
		(width 0.088646)
		(layer "In6.Cu")
		(net "M_C_CPU0_SB_DQ<27>")
	)
	(arc
		(start 343.50833 -228.45903)
		(mid 343.458166 -228.271892)
		(end 343.321132 -228.134926)
		(width 0.088646)
		(layer "In6.Cu")
		(net "M_C_CPU0_SB_DQ<27>")
	)
	(arc
		(start 337.212432 -227.969318)
		(mid 337.025234 -228.019461)
		(end 336.838036 -227.969318)
		(width 0.088646)
		(layer "In6.Cu")
		(net "M_C_CPU0_SB_DQ<27>")
	)
	(arc
		(start 333.078582 -226.341686)
		(mid 332.942213 -226.285244)
		(end 332.79588 -226.265994)
		(width 0.088646)
		(layer "In6.Cu")
		(net "M_C_CPU0_SB_DQ<27>")
	)
	(arc
		(start 339.092032 -227.969318)
		(mid 338.904834 -228.019461)
		(end 338.717636 -227.969318)
		(width 0.088646)
		(layer "In6.Cu")
		(net "M_C_CPU0_SB_DQ<27>")
	)
	(arc
		(start 340.127082 -228.783388)
		(mid 339.992149 -228.650034)
		(end 339.939884 -228.467666)
		(width 0.088646)
		(layer "In6.Cu")
		(net "M_C_CPU0_SB_DQ<27>")
	)
	(arc
		(start 334.008222 -226.33559)
		(mid 333.72979 -226.265744)
		(end 333.452978 -226.341686)
		(width 0.088646)
		(layer "In6.Cu")
		(net "M_C_CPU0_SB_DQ<27>")
	)
	(arc
		(start 341.99195 -228.774752)
		(mid 341.715475 -228.707432)
		(end 341.441278 -228.783388)
		(width 0.088646)
		(layer "In6.Cu")
		(net "M_C_CPU0_SB_DQ<27>")
	)
	(arc
		(start 342.660732 -228.299772)
		(mid 342.593237 -228.36703)
		(end 342.56853 -228.45903)
		(width 0.088646)
		(layer "In6.Cu")
		(net "M_C_CPU0_SB_DQ<27>")
	)
	(segment
		(start 280.689558 -203.311252)
		(end 280.689558 -202.985624)
		(width 0.20066)
		(layer "F.Cu")
		(net "M_C_CPU0_SB_DQ<26>")
	)
	(segment
		(start 281.497278 -203.266802)
		(end 281.285442 -203.478638)
		(width 0.20066)
		(layer "F.Cu")
		(net "M_C_CPU0_SB_DQ<26>")
	)
	(segment
		(start 281.285442 -203.478638)
		(end 280.856944 -203.478638)
		(width 0.20066)
		(layer "F.Cu")
		(net "M_C_CPU0_SB_DQ<26>")
	)
	(segment
		(start 283.916882 -203.266802)
		(end 282.811982 -203.266802)
		(width 0.20066)
		(layer "F.Cu")
		(net "M_C_CPU0_SB_DQ<26>")
	)
	(segment
		(start 276.415246 -203.266802)
		(end 275.268182 -203.266802)
		(width 0.20066)
		(layer "F.Cu")
		(net "M_C_CPU0_SB_DQ<26>")
	)
	(segment
		(start 279.912826 -202.84186)
		(end 277.852886 -202.84186)
		(width 0.1016)
		(layer "F.Cu")
		(net "M_C_CPU0_SB_DQ<26>")
	)
	(segment
		(start 280.545794 -202.84186)
		(end 279.912826 -202.84186)
		(width 0.20066)
		(layer "F.Cu")
		(net "M_C_CPU0_SB_DQ<26>")
	)
	(segment
		(start 344.54338 -229.808786)
		(end 344.543634 -229.808532)
		(width 0.20066)
		(layer "F.Cu")
		(net "M_C_CPU0_SB_DQ<26>")
	)
	(segment
		(start 344.543634 -229.808532)
		(end 344.543634 -229.272846)
		(width 0.20066)
		(layer "F.Cu")
		(net "M_C_CPU0_SB_DQ<26>")
	)
	(segment
		(start 282.811982 -203.266802)
		(end 281.497278 -203.266802)
		(width 0.20066)
		(layer "F.Cu")
		(net "M_C_CPU0_SB_DQ<26>")
	)
	(segment
		(start 277.58771 -202.8317)
		(end 276.850348 -202.8317)
		(width 0.20066)
		(layer "F.Cu")
		(net "M_C_CPU0_SB_DQ<26>")
	)
	(segment
		(start 277.852886 -202.84186)
		(end 277.59787 -202.84186)
		(width 0.101854)
		(layer "F.Cu")
		(net "M_C_CPU0_SB_DQ<26>")
	)
	(segment
		(start 276.850348 -202.8317)
		(end 276.415246 -203.266802)
		(width 0.20066)
		(layer "F.Cu")
		(net "M_C_CPU0_SB_DQ<26>")
	)
	(segment
		(start 280.856944 -203.478638)
		(end 280.689558 -203.311252)
		(width 0.20066)
		(layer "F.Cu")
		(net "M_C_CPU0_SB_DQ<26>")
	)
	(segment
		(start 280.689558 -202.985624)
		(end 280.545794 -202.84186)
		(width 0.20066)
		(layer "F.Cu")
		(net "M_C_CPU0_SB_DQ<26>")
	)
	(segment
		(start 277.59787 -202.84186)
		(end 277.58771 -202.8317)
		(width 0.101854)
		(layer "F.Cu")
		(net "M_C_CPU0_SB_DQ<26>")
	)
	(segment
		(start 294.569642 -203.54798)
		(end 293.82593 -203.54798)
		(width 0.18288)
		(layer "In6.Cu")
		(net "M_C_CPU0_SB_DQ<26>")
	)
	(segment
		(start 309.042054 -205.34884)
		(end 308.73827 -205.34884)
		(width 0.18288)
		(layer "In6.Cu")
		(net "M_C_CPU0_SB_DQ<26>")
	)
	(segment
		(start 305.655218 -204.390498)
		(end 305.472338 -204.573378)
		(width 0.18288)
		(layer "In6.Cu")
		(net "M_C_CPU0_SB_DQ<26>")
	)
	(segment
		(start 306.796694 -203.662026)
		(end 305.838098 -203.662026)
		(width 0.18288)
		(layer "In6.Cu")
		(net "M_C_CPU0_SB_DQ<26>")
	)
	(segment
		(start 337.227164 -228.957124)
		(end 337.212432 -228.948488)
		(width 0.088646)
		(layer "In6.Cu")
		(net "M_C_CPU0_SB_DQ<26>")
	)
	(segment
		(start 296.536364 -203.00188)
		(end 296.376344 -202.84186)
		(width 0.18288)
		(layer "In6.Cu")
		(net "M_C_CPU0_SB_DQ<26>")
	)
	(segment
		(start 284.928818 -202.845162)
		(end 284.507178 -203.266802)
		(width 0.18288)
		(layer "In6.Cu")
		(net "M_C_CPU0_SB_DQ<26>")
	)
	(segment
		(start 290.025074 -202.590654)
		(end 290.025074 -203.118212)
		(width 0.18288)
		(layer "In6.Cu")
		(net "M_C_CPU0_SB_DQ<26>")
	)
	(segment
		(start 302.928528 -202.84186)
		(end 297.389804 -202.84186)
		(width 0.18288)
		(layer "In6.Cu")
		(net "M_C_CPU0_SB_DQ<26>")
	)
	(segment
		(start 313.558428 -207.448658)
		(end 313.558428 -206.75346)
		(width 0.18288)
		(layer "In6.Cu")
		(net "M_C_CPU0_SB_DQ<26>")
	)
	(segment
		(start 290.718494 -202.590654)
		(end 290.535614 -202.407774)
		(width 0.18288)
		(layer "In6.Cu")
		(net "M_C_CPU0_SB_DQ<26>")
	)
	(segment
		(start 304.964338 -204.390498)
		(end 304.964338 -203.844906)
		(width 0.18288)
		(layer "In6.Cu")
		(net "M_C_CPU0_SB_DQ<26>")
	)
	(segment
		(start 290.718494 -203.118212)
		(end 290.718494 -202.590654)
		(width 0.18288)
		(layer "In6.Cu")
		(net "M_C_CPU0_SB_DQ<26>")
	)
	(segment
		(start 310.453024 -205.735936)
		(end 310.453024 -205.477364)
		(width 0.18288)
		(layer "In6.Cu")
		(net "M_C_CPU0_SB_DQ<26>")
	)
	(segment
		(start 325.84771 -221.02064)
		(end 317.484252 -212.657182)
		(width 0.18288)
		(layer "In6.Cu")
		(net "M_C_CPU0_SB_DQ<26>")
	)
	(segment
		(start 316.102746 -209.321908)
		(end 314.080906 -207.971136)
		(width 0.18288)
		(layer "In6.Cu")
		(net "M_C_CPU0_SB_DQ<26>")
	)
	(segment
		(start 310.943498 -205.967838)
		(end 310.684926 -205.967838)
		(width 0.18288)
		(layer "In6.Cu")
		(net "M_C_CPU0_SB_DQ<26>")
	)
	(segment
		(start 295.085008 -203.689458)
		(end 294.71112 -203.689458)
		(width 0.18288)
		(layer "In6.Cu")
		(net "M_C_CPU0_SB_DQ<26>")
	)
	(segment
		(start 290.207954 -202.407774)
		(end 290.025074 -202.590654)
		(width 0.18288)
		(layer "In6.Cu")
		(net "M_C_CPU0_SB_DQ<26>")
	)
	(segment
		(start 290.535614 -202.407774)
		(end 290.207954 -202.407774)
		(width 0.18288)
		(layer "In6.Cu")
		(net "M_C_CPU0_SB_DQ<26>")
	)
	(segment
		(start 296.696384 -203.585572)
		(end 296.536364 -203.425552)
		(width 0.18288)
		(layer "In6.Cu")
		(net "M_C_CPU0_SB_DQ<26>")
	)
	(segment
		(start 297.229784 -203.00188)
		(end 297.229784 -203.425552)
		(width 0.18288)
		(layer "In6.Cu")
		(net "M_C_CPU0_SB_DQ<26>")
	)
	(segment
		(start 293.82593 -203.54798)
		(end 293.080186 -202.802236)
		(width 0.18288)
		(layer "In6.Cu")
		(net "M_C_CPU0_SB_DQ<26>")
	)
	(segment
		(start 340.127082 -229.762304)
		(end 340.11235 -229.77094)
		(width 0.088646)
		(layer "In6.Cu")
		(net "M_C_CPU0_SB_DQ<26>")
	)
	(segment
		(start 342.006682 -229.762304)
		(end 341.99195 -229.77094)
		(width 0.088646)
		(layer "In6.Cu")
		(net "M_C_CPU0_SB_DQ<26>")
	)
	(segment
		(start 296.376344 -202.84186)
		(end 295.932606 -202.84186)
		(width 0.18288)
		(layer "In6.Cu")
		(net "M_C_CPU0_SB_DQ<26>")
	)
	(segment
		(start 295.932606 -202.84186)
		(end 295.085008 -203.689458)
		(width 0.18288)
		(layer "In6.Cu")
		(net "M_C_CPU0_SB_DQ<26>")
	)
	(segment
		(start 309.407814 -204.525626)
		(end 309.224934 -204.708506)
		(width 0.18288)
		(layer "In6.Cu")
		(net "M_C_CPU0_SB_DQ<26>")
	)
	(segment
		(start 303.748694 -203.662026)
		(end 302.928528 -202.84186)
		(width 0.18288)
		(layer "In6.Cu")
		(net "M_C_CPU0_SB_DQ<26>")
	)
	(segment
		(start 304.781458 -203.662026)
		(end 303.748694 -203.662026)
		(width 0.18288)
		(layer "In6.Cu")
		(net "M_C_CPU0_SB_DQ<26>")
	)
	(segment
		(start 339.279484 -229.28834)
		(end 339.279484 -229.272846)
		(width 0.088646)
		(layer "In6.Cu")
		(net "M_C_CPU0_SB_DQ<26>")
	)
	(segment
		(start 311.535572 -205.375764)
		(end 310.943498 -205.967838)
		(width 0.18288)
		(layer "In6.Cu")
		(net "M_C_CPU0_SB_DQ<26>")
	)
	(segment
		(start 309.224934 -204.708506)
		(end 309.224934 -205.16596)
		(width 0.18288)
		(layer "In6.Cu")
		(net "M_C_CPU0_SB_DQ<26>")
	)
	(segment
		(start 332.523846 -227.326698)
		(end 332.513432 -227.320602)
		(width 0.088646)
		(layer "In6.Cu")
		(net "M_C_CPU0_SB_DQ<26>")
	)
	(segment
		(start 286.277558 -202.845162)
		(end 284.928818 -202.845162)
		(width 0.18288)
		(layer "In6.Cu")
		(net "M_C_CPU0_SB_DQ<26>")
	)
	(segment
		(start 296.536364 -203.425552)
		(end 296.536364 -203.00188)
		(width 0.18288)
		(layer "In6.Cu")
		(net "M_C_CPU0_SB_DQ<26>")
	)
	(segment
		(start 332.396338 -227.230686)
		(end 330.576936 -225.411284)
		(width 0.088646)
		(layer "In6.Cu")
		(net "M_C_CPU0_SB_DQ<26>")
	)
	(segment
		(start 335.050384 -228.459284)
		(end 335.050384 -228.452172)
		(width 0.088646)
		(layer "In6.Cu")
		(net "M_C_CPU0_SB_DQ<26>")
	)
	(segment
		(start 317.484252 -212.657182)
		(end 316.102746 -209.321908)
		(width 0.18288)
		(layer "In6.Cu")
		(net "M_C_CPU0_SB_DQ<26>")
	)
	(segment
		(start 335.050638 -228.474778)
		(end 335.050384 -228.459284)
		(width 0.088646)
		(layer "In6.Cu")
		(net "M_C_CPU0_SB_DQ<26>")
	)
	(segment
		(start 308.534054 -205.144624)
		(end 308.534054 -204.708506)
		(width 0.18288)
		(layer "In6.Cu")
		(net "M_C_CPU0_SB_DQ<26>")
	)
	(segment
		(start 284.507178 -203.266802)
		(end 283.916882 -203.266802)
		(width 0.18288)
		(layer "In6.Cu")
		(net "M_C_CPU0_SB_DQ<26>")
	)
	(segment
		(start 291.860732 -203.301092)
		(end 290.901374 -203.301092)
		(width 0.18288)
		(layer "In6.Cu")
		(net "M_C_CPU0_SB_DQ<26>")
	)
	(segment
		(start 339.100922 -228.953568)
		(end 339.092032 -228.948488)
		(width 0.088646)
		(layer "In6.Cu")
		(net "M_C_CPU0_SB_DQ<26>")
	)
	(segment
		(start 297.229784 -203.425552)
		(end 297.069764 -203.585572)
		(width 0.18288)
		(layer "In6.Cu")
		(net "M_C_CPU0_SB_DQ<26>")
	)
	(segment
		(start 330.576936 -225.411284)
		(end 330.41971 -225.411284)
		(width 0.088646)
		(layer "In6.Cu")
		(net "M_C_CPU0_SB_DQ<26>")
	)
	(segment
		(start 335.898236 -228.948488)
		(end 335.887822 -228.954584)
		(width 0.088646)
		(layer "In6.Cu")
		(net "M_C_CPU0_SB_DQ<26>")
	)
	(segment
		(start 310.781954 -204.889862)
		(end 310.417718 -204.525626)
		(width 0.18288)
		(layer "In6.Cu")
		(net "M_C_CPU0_SB_DQ<26>")
	)
	(segment
		(start 289.842194 -203.301092)
		(end 289.151314 -203.301092)
		(width 0.18288)
		(layer "In6.Cu")
		(net "M_C_CPU0_SB_DQ<26>")
	)
	(segment
		(start 290.025074 -203.118212)
		(end 289.842194 -203.301092)
		(width 0.18288)
		(layer "In6.Cu")
		(net "M_C_CPU0_SB_DQ<26>")
	)
	(segment
		(start 310.417718 -204.525626)
		(end 309.407814 -204.525626)
		(width 0.18288)
		(layer "In6.Cu")
		(net "M_C_CPU0_SB_DQ<26>")
	)
	(segment
		(start 308.534054 -204.708506)
		(end 308.351174 -204.525626)
		(width 0.18288)
		(layer "In6.Cu")
		(net "M_C_CPU0_SB_DQ<26>")
	)
	(segment
		(start 325.84771 -223.80575)
		(end 325.84771 -221.02064)
		(width 0.18288)
		(layer "In6.Cu")
		(net "M_C_CPU0_SB_DQ<26>")
	)
	(segment
		(start 297.069764 -203.585572)
		(end 296.696384 -203.585572)
		(width 0.18288)
		(layer "In6.Cu")
		(net "M_C_CPU0_SB_DQ<26>")
	)
	(segment
		(start 294.71112 -203.689458)
		(end 294.569642 -203.54798)
		(width 0.18288)
		(layer "In6.Cu")
		(net "M_C_CPU0_SB_DQ<26>")
	)
	(segment
		(start 288.428938 -202.578716)
		(end 286.544004 -202.578716)
		(width 0.18288)
		(layer "In6.Cu")
		(net "M_C_CPU0_SB_DQ<26>")
	)
	(segment
		(start 336.287364 -228.957124)
		(end 336.272632 -228.948488)
		(width 0.088646)
		(layer "In6.Cu")
		(net "M_C_CPU0_SB_DQ<26>")
	)
	(segment
		(start 293.080186 -202.802236)
		(end 292.359588 -202.802236)
		(width 0.18288)
		(layer "In6.Cu")
		(net "M_C_CPU0_SB_DQ<26>")
	)
	(segment
		(start 313.558428 -206.75346)
		(end 312.180732 -205.375764)
		(width 0.18288)
		(layer "In6.Cu")
		(net "M_C_CPU0_SB_DQ<26>")
	)
	(segment
		(start 305.655218 -203.844906)
		(end 305.655218 -204.390498)
		(width 0.18288)
		(layer "In6.Cu")
		(net "M_C_CPU0_SB_DQ<26>")
	)
	(segment
		(start 341.066882 -229.762304)
		(end 341.05215 -229.77094)
		(width 0.088646)
		(layer "In6.Cu")
		(net "M_C_CPU0_SB_DQ<26>")
	)
	(segment
		(start 305.472338 -204.573378)
		(end 305.147218 -204.573378)
		(width 0.18288)
		(layer "In6.Cu")
		(net "M_C_CPU0_SB_DQ<26>")
	)
	(segment
		(start 309.224934 -205.16596)
		(end 309.042054 -205.34884)
		(width 0.18288)
		(layer "In6.Cu")
		(net "M_C_CPU0_SB_DQ<26>")
	)
	(segment
		(start 305.147218 -204.573378)
		(end 304.964338 -204.390498)
		(width 0.18288)
		(layer "In6.Cu")
		(net "M_C_CPU0_SB_DQ<26>")
	)
	(segment
		(start 286.544004 -202.578716)
		(end 286.277558 -202.845162)
		(width 0.18288)
		(layer "In6.Cu")
		(net "M_C_CPU0_SB_DQ<26>")
	)
	(segment
		(start 297.389804 -202.84186)
		(end 297.229784 -203.00188)
		(width 0.18288)
		(layer "In6.Cu")
		(net "M_C_CPU0_SB_DQ<26>")
	)
	(segment
		(start 289.151314 -203.301092)
		(end 288.428938 -202.578716)
		(width 0.18288)
		(layer "In6.Cu")
		(net "M_C_CPU0_SB_DQ<26>")
	)
	(segment
		(start 327.453244 -225.411284)
		(end 325.84771 -223.80575)
		(width 0.18288)
		(layer "In6.Cu")
		(net "M_C_CPU0_SB_DQ<26>")
	)
	(segment
		(start 310.453024 -205.477364)
		(end 310.781954 -205.148434)
		(width 0.18288)
		(layer "In6.Cu")
		(net "M_C_CPU0_SB_DQ<26>")
	)
	(segment
		(start 305.838098 -203.662026)
		(end 305.655218 -203.844906)
		(width 0.18288)
		(layer "In6.Cu")
		(net "M_C_CPU0_SB_DQ<26>")
	)
	(segment
		(start 292.359588 -202.802236)
		(end 291.860732 -203.301092)
		(width 0.18288)
		(layer "In6.Cu")
		(net "M_C_CPU0_SB_DQ<26>")
	)
	(segment
		(start 330.41971 -225.411284)
		(end 327.453244 -225.411284)
		(width 0.18288)
		(layer "In6.Cu")
		(net "M_C_CPU0_SB_DQ<26>")
	)
	(segment
		(start 310.684926 -205.967838)
		(end 310.453024 -205.735936)
		(width 0.18288)
		(layer "In6.Cu")
		(net "M_C_CPU0_SB_DQ<26>")
	)
	(segment
		(start 304.964338 -203.844906)
		(end 304.781458 -203.662026)
		(width 0.18288)
		(layer "In6.Cu")
		(net "M_C_CPU0_SB_DQ<26>")
	)
	(segment
		(start 314.080906 -207.971136)
		(end 313.558428 -207.448658)
		(width 0.18288)
		(layer "In6.Cu")
		(net "M_C_CPU0_SB_DQ<26>")
	)
	(segment
		(start 307.660294 -204.525626)
		(end 306.796694 -203.662026)
		(width 0.18288)
		(layer "In6.Cu")
		(net "M_C_CPU0_SB_DQ<26>")
	)
	(segment
		(start 312.180732 -205.375764)
		(end 311.535572 -205.375764)
		(width 0.18288)
		(layer "In6.Cu")
		(net "M_C_CPU0_SB_DQ<26>")
	)
	(segment
		(start 308.73827 -205.34884)
		(end 308.534054 -205.144624)
		(width 0.18288)
		(layer "In6.Cu")
		(net "M_C_CPU0_SB_DQ<26>")
	)
	(segment
		(start 308.351174 -204.525626)
		(end 307.660294 -204.525626)
		(width 0.18288)
		(layer "In6.Cu")
		(net "M_C_CPU0_SB_DQ<26>")
	)
	(segment
		(start 338.166964 -228.957124)
		(end 338.152232 -228.948488)
		(width 0.088646)
		(layer "In6.Cu")
		(net "M_C_CPU0_SB_DQ<26>")
	)
	(segment
		(start 310.781954 -205.148434)
		(end 310.781954 -204.889862)
		(width 0.18288)
		(layer "In6.Cu")
		(net "M_C_CPU0_SB_DQ<26>")
	)
	(segment
		(start 290.901374 -203.301092)
		(end 290.718494 -203.118212)
		(width 0.18288)
		(layer "In6.Cu")
		(net "M_C_CPU0_SB_DQ<26>")
	)
	(segment
		(start 334.58023 -227.659184)
		(end 334.58023 -227.636324)
		(width 0.088646)
		(layer "In6.Cu")
		(net "M_C_CPU0_SB_DQ<26>")
	)
	(segment
		(start 334.018636 -227.320602)
		(end 334.008222 -227.326698)
		(width 0.088646)
		(layer "In6.Cu")
		(net "M_C_CPU0_SB_DQ<26>")
	)
	(arc
		(start 333.078582 -227.320602)
		(mid 332.802023 -227.396345)
		(end 332.523846 -227.326698)
		(width 0.088646)
		(layer "In6.Cu")
		(net "M_C_CPU0_SB_DQ<26>")
	)
	(arc
		(start 334.393032 -227.320602)
		(mid 334.205834 -227.270459)
		(end 334.018636 -227.320602)
		(width 0.088646)
		(layer "In6.Cu")
		(net "M_C_CPU0_SB_DQ<26>")
	)
	(arc
		(start 335.332578 -228.948488)
		(mid 335.13 -228.748315)
		(end 335.050638 -228.474778)
		(width 0.088646)
		(layer "In6.Cu")
		(net "M_C_CPU0_SB_DQ<26>")
	)
	(arc
		(start 334.58023 -227.636324)
		(mid 334.52796 -227.453959)
		(end 334.393032 -227.320602)
		(width 0.088646)
		(layer "In6.Cu")
		(net "M_C_CPU0_SB_DQ<26>")
	)
	(arc
		(start 339.092032 -228.948488)
		(mid 338.904834 -228.898345)
		(end 338.717636 -228.948488)
		(width 0.088646)
		(layer "In6.Cu")
		(net "M_C_CPU0_SB_DQ<26>")
	)
	(arc
		(start 342.381078 -229.762304)
		(mid 342.19388 -229.712161)
		(end 342.006682 -229.762304)
		(width 0.088646)
		(layer "In6.Cu")
		(net "M_C_CPU0_SB_DQ<26>")
	)
	(arc
		(start 338.152232 -228.948488)
		(mid 337.965034 -228.898345)
		(end 337.777836 -228.948488)
		(width 0.088646)
		(layer "In6.Cu")
		(net "M_C_CPU0_SB_DQ<26>")
	)
	(arc
		(start 337.212432 -228.948488)
		(mid 337.025234 -228.898345)
		(end 336.838036 -228.948488)
		(width 0.088646)
		(layer "In6.Cu")
		(net "M_C_CPU0_SB_DQ<26>")
	)
	(arc
		(start 336.838036 -228.948488)
		(mid 336.563837 -229.024323)
		(end 336.287364 -228.957124)
		(width 0.088646)
		(layer "In6.Cu")
		(net "M_C_CPU0_SB_DQ<26>")
	)
	(arc
		(start 339.279484 -229.272846)
		(mid 339.231805 -229.089946)
		(end 339.100922 -228.953568)
		(width 0.088646)
		(layer "In6.Cu")
		(net "M_C_CPU0_SB_DQ<26>")
	)
	(arc
		(start 332.513432 -227.320602)
		(mid 332.451943 -227.279476)
		(end 332.396338 -227.230686)
		(width 0.088646)
		(layer "In6.Cu")
		(net "M_C_CPU0_SB_DQ<26>")
	)
	(arc
		(start 334.008222 -227.326698)
		(mid 333.72979 -227.396544)
		(end 333.452978 -227.320602)
		(width 0.088646)
		(layer "In6.Cu")
		(net "M_C_CPU0_SB_DQ<26>")
	)
	(arc
		(start 341.05215 -229.77094)
		(mid 340.775675 -229.83826)
		(end 340.501478 -229.762304)
		(width 0.088646)
		(layer "In6.Cu")
		(net "M_C_CPU0_SB_DQ<26>")
	)
	(arc
		(start 340.501478 -229.762304)
		(mid 340.31428 -229.712161)
		(end 340.127082 -229.762304)
		(width 0.088646)
		(layer "In6.Cu")
		(net "M_C_CPU0_SB_DQ<26>")
	)
	(arc
		(start 335.887822 -228.954584)
		(mid 335.60939 -229.02443)
		(end 335.332578 -228.948488)
		(width 0.088646)
		(layer "In6.Cu")
		(net "M_C_CPU0_SB_DQ<26>")
	)
	(arc
		(start 341.441278 -229.762304)
		(mid 341.25408 -229.712161)
		(end 341.066882 -229.762304)
		(width 0.088646)
		(layer "In6.Cu")
		(net "M_C_CPU0_SB_DQ<26>")
	)
	(arc
		(start 343.07145 -229.717346)
		(mid 343.006953 -229.734232)
		(end 342.946482 -229.762304)
		(width 0.088646)
		(layer "In6.Cu")
		(net "M_C_CPU0_SB_DQ<26>")
	)
	(arc
		(start 343.829894 -229.671626)
		(mid 343.449451 -229.674228)
		(end 343.07145 -229.717346)
		(width 0.088646)
		(layer "In6.Cu")
		(net "M_C_CPU0_SB_DQ<26>")
	)
	(arc
		(start 335.050384 -228.452172)
		(mid 334.998408 -228.268773)
		(end 334.862932 -228.134672)
		(width 0.088646)
		(layer "In6.Cu")
		(net "M_C_CPU0_SB_DQ<26>")
	)
	(arc
		(start 337.777836 -228.948488)
		(mid 337.503637 -229.024323)
		(end 337.227164 -228.957124)
		(width 0.088646)
		(layer "In6.Cu")
		(net "M_C_CPU0_SB_DQ<26>")
	)
	(arc
		(start 339.561678 -229.762304)
		(mid 339.358855 -229.562073)
		(end 339.279484 -229.28834)
		(width 0.088646)
		(layer "In6.Cu")
		(net "M_C_CPU0_SB_DQ<26>")
	)
	(arc
		(start 340.11235 -229.77094)
		(mid 339.835875 -229.83826)
		(end 339.561678 -229.762304)
		(width 0.088646)
		(layer "In6.Cu")
		(net "M_C_CPU0_SB_DQ<26>")
	)
	(arc
		(start 342.946482 -229.762304)
		(mid 342.66378 -229.83808)
		(end 342.381078 -229.762304)
		(width 0.088646)
		(layer "In6.Cu")
		(net "M_C_CPU0_SB_DQ<26>")
	)
	(arc
		(start 338.717636 -228.948488)
		(mid 338.443437 -229.024323)
		(end 338.166964 -228.957124)
		(width 0.088646)
		(layer "In6.Cu")
		(net "M_C_CPU0_SB_DQ<26>")
	)
	(arc
		(start 336.272632 -228.948488)
		(mid 336.085434 -228.898345)
		(end 335.898236 -228.948488)
		(width 0.088646)
		(layer "In6.Cu")
		(net "M_C_CPU0_SB_DQ<26>")
	)
	(arc
		(start 341.99195 -229.77094)
		(mid 341.715475 -229.83826)
		(end 341.441278 -229.762304)
		(width 0.088646)
		(layer "In6.Cu")
		(net "M_C_CPU0_SB_DQ<26>")
	)
	(arc
		(start 334.862932 -228.134672)
		(mid 334.659451 -227.933868)
		(end 334.58023 -227.659184)
		(width 0.088646)
		(layer "In6.Cu")
		(net "M_C_CPU0_SB_DQ<26>")
	)
	(arc
		(start 333.452978 -227.320602)
		(mid 333.26578 -227.270459)
		(end 333.078582 -227.320602)
		(width 0.088646)
		(layer "In6.Cu")
		(net "M_C_CPU0_SB_DQ<26>")
	)
	(arc
		(start 344.543634 -229.272846)
		(mid 344.243664 -229.574058)
		(end 343.829894 -229.671626)
		(width 0.088646)
		(layer "In6.Cu")
		(net "M_C_CPU0_SB_DQ<26>")
	)
	(segment
		(start 343.133934 -228.99497)
		(end 343.13368 -228.994716)
		(width 0.20066)
		(layer "F.Cu")
		(net "M_C_CPU0_SB_DQ<25>")
	)
	(segment
		(start 276.138386 -201.991722)
		(end 274.152868 -201.991722)
		(width 0.1016)
		(layer "F.Cu")
		(net "M_C_CPU0_SB_DQ<25>")
	)
	(segment
		(start 273.37258 -202.145392)
		(end 273.37258 -202.47356)
		(width 0.20066)
		(layer "F.Cu")
		(net "M_C_CPU0_SB_DQ<25>")
	)
	(segment
		(start 272.502376 -202.416664)
		(end 271.168114 -202.416664)
		(width 0.20066)
		(layer "F.Cu")
		(net "M_C_CPU0_SB_DQ<25>")
	)
	(segment
		(start 274.152868 -201.991722)
		(end 274.143978 -201.982832)
		(width 0.1016)
		(layer "F.Cu")
		(net "M_C_CPU0_SB_DQ<25>")
	)
	(segment
		(start 272.713704 -202.627992)
		(end 272.502376 -202.416664)
		(width 0.20066)
		(layer "F.Cu")
		(net "M_C_CPU0_SB_DQ<25>")
	)
	(segment
		(start 343.13368 -228.994716)
		(end 343.13368 -228.45903)
		(width 0.20066)
		(layer "F.Cu")
		(net "M_C_CPU0_SB_DQ<25>")
	)
	(segment
		(start 278.711914 -202.416664)
		(end 277.072598 -202.416664)
		(width 0.20066)
		(layer "F.Cu")
		(net "M_C_CPU0_SB_DQ<25>")
	)
	(segment
		(start 279.816814 -202.416664)
		(end 278.711914 -202.416664)
		(width 0.20066)
		(layer "F.Cu")
		(net "M_C_CPU0_SB_DQ<25>")
	)
	(segment
		(start 276.469094 -201.991722)
		(end 276.138386 -201.991722)
		(width 0.101854)
		(layer "F.Cu")
		(net "M_C_CPU0_SB_DQ<25>")
	)
	(segment
		(start 273.53514 -201.982832)
		(end 273.37258 -202.145392)
		(width 0.20066)
		(layer "F.Cu")
		(net "M_C_CPU0_SB_DQ<25>")
	)
	(segment
		(start 277.072598 -202.416664)
		(end 276.647656 -201.991722)
		(width 0.20066)
		(layer "F.Cu")
		(net "M_C_CPU0_SB_DQ<25>")
	)
	(segment
		(start 273.37258 -202.47356)
		(end 273.218148 -202.627992)
		(width 0.20066)
		(layer "F.Cu")
		(net "M_C_CPU0_SB_DQ<25>")
	)
	(segment
		(start 276.647656 -201.991722)
		(end 276.469094 -201.991722)
		(width 0.20066)
		(layer "F.Cu")
		(net "M_C_CPU0_SB_DQ<25>")
	)
	(segment
		(start 274.143978 -201.982832)
		(end 273.53514 -201.982832)
		(width 0.20066)
		(layer "F.Cu")
		(net "M_C_CPU0_SB_DQ<25>")
	)
	(segment
		(start 273.218148 -202.627992)
		(end 272.713704 -202.627992)
		(width 0.20066)
		(layer "F.Cu")
		(net "M_C_CPU0_SB_DQ<25>")
	)
	(segment
		(start 341.921846 -228.954584)
		(end 341.911432 -228.948488)
		(width 0.088646)
		(layer "In6.Cu")
		(net "M_C_CPU0_SB_DQ<25>")
	)
	(segment
		(start 300.296326 -200.816972)
		(end 299.97146 -201.141838)
		(width 0.18288)
		(layer "In6.Cu")
		(net "M_C_CPU0_SB_DQ<25>")
	)
	(segment
		(start 340.986364 -228.957124)
		(end 340.971632 -228.948488)
		(width 0.088646)
		(layer "In6.Cu")
		(net "M_C_CPU0_SB_DQ<25>")
	)
	(segment
		(start 296.095674 -201.141838)
		(end 295.24579 -201.991722)
		(width 0.18288)
		(layer "In6.Cu")
		(net "M_C_CPU0_SB_DQ<25>")
	)
	(segment
		(start 290.867846 -201.14133)
		(end 290.558728 -200.832212)
		(width 0.18288)
		(layer "In6.Cu")
		(net "M_C_CPU0_SB_DQ<25>")
	)
	(segment
		(start 306.771294 -201.884026)
		(end 305.946048 -201.884026)
		(width 0.18288)
		(layer "In6.Cu")
		(net "M_C_CPU0_SB_DQ<25>")
	)
	(segment
		(start 340.046564 -228.957124)
		(end 340.031832 -228.948488)
		(width 0.088646)
		(layer "In6.Cu")
		(net "M_C_CPU0_SB_DQ<25>")
	)
	(segment
		(start 339.187536 -228.134672)
		(end 339.177122 -228.140768)
		(width 0.088646)
		(layer "In6.Cu")
		(net "M_C_CPU0_SB_DQ<25>")
	)
	(segment
		(start 311.165494 -203.611226)
		(end 310.352694 -202.798426)
		(width 0.18288)
		(layer "In6.Cu")
		(net "M_C_CPU0_SB_DQ<25>")
	)
	(segment
		(start 301.3583 -201.141838)
		(end 300.989746 -201.141838)
		(width 0.18288)
		(layer "In6.Cu")
		(net "M_C_CPU0_SB_DQ<25>")
	)
	(segment
		(start 308.559454 -202.981306)
		(end 308.376574 -202.798426)
		(width 0.18288)
		(layer "In6.Cu")
		(net "M_C_CPU0_SB_DQ<25>")
	)
	(segment
		(start 281.567636 -201.37501)
		(end 281.384756 -201.19213)
		(width 0.18288)
		(layer "In6.Cu")
		(net "M_C_CPU0_SB_DQ<25>")
	)
	(segment
		(start 305.946048 -201.884026)
		(end 305.763168 -202.066906)
		(width 0.18288)
		(layer "In6.Cu")
		(net "M_C_CPU0_SB_DQ<25>")
	)
	(segment
		(start 287.712658 -200.842372)
		(end 287.318196 -200.842372)
		(width 0.18288)
		(layer "In6.Cu")
		(net "M_C_CPU0_SB_DQ<25>")
	)
	(segment
		(start 281.955494 -201.83094)
		(end 281.750516 -201.83094)
		(width 0.18288)
		(layer "In6.Cu")
		(net "M_C_CPU0_SB_DQ<25>")
	)
	(segment
		(start 290.558728 -200.832212)
		(end 290.174426 -200.832212)
		(width 0.18288)
		(layer "In6.Cu")
		(net "M_C_CPU0_SB_DQ<25>")
	)
	(segment
		(start 286.22879 -201.14133)
		(end 285.37916 -201.99096)
		(width 0.18288)
		(layer "In6.Cu")
		(net "M_C_CPU0_SB_DQ<25>")
	)
	(segment
		(start 335.52003 -227.65258)
		(end 335.52003 -227.64496)
		(width 0.088646)
		(layer "In6.Cu")
		(net "M_C_CPU0_SB_DQ<25>")
	)
	(segment
		(start 303.824894 -201.884026)
		(end 303.082706 -201.141838)
		(width 0.18288)
		(layer "In6.Cu")
		(net "M_C_CPU0_SB_DQ<25>")
	)
	(segment
		(start 280.874216 -201.37501)
		(end 280.874216 -201.64806)
		(width 0.18288)
		(layer "In6.Cu")
		(net "M_C_CPU0_SB_DQ<25>")
	)
	(segment
		(start 332.064868 -226.08413)
		(end 332.064868 -225.838004)
		(width 0.088646)
		(layer "In6.Cu")
		(net "M_C_CPU0_SB_DQ<25>")
	)
	(segment
		(start 285.37916 -201.99096)
		(end 282.115514 -201.99096)
		(width 0.18288)
		(layer "In6.Cu")
		(net "M_C_CPU0_SB_DQ<25>")
	)
	(segment
		(start 294.729662 -201.991722)
		(end 293.87927 -201.14133)
		(width 0.18288)
		(layer "In6.Cu")
		(net "M_C_CPU0_SB_DQ<25>")
	)
	(segment
		(start 308.559454 -203.28001)
		(end 308.559454 -202.981306)
		(width 0.18288)
		(layer "In6.Cu")
		(net "M_C_CPU0_SB_DQ<25>")
	)
	(segment
		(start 305.255168 -202.57643)
		(end 305.072288 -202.39355)
		(width 0.18288)
		(layer "In6.Cu")
		(net "M_C_CPU0_SB_DQ<25>")
	)
	(segment
		(start 288.011616 -201.14133)
		(end 287.712658 -200.842372)
		(width 0.18288)
		(layer "In6.Cu")
		(net "M_C_CPU0_SB_DQ<25>")
	)
	(segment
		(start 299.97146 -201.141838)
		(end 296.095674 -201.141838)
		(width 0.18288)
		(layer "In6.Cu")
		(net "M_C_CPU0_SB_DQ<25>")
	)
	(segment
		(start 302.05172 -200.816972)
		(end 301.683166 -200.816972)
		(width 0.18288)
		(layer "In6.Cu")
		(net "M_C_CPU0_SB_DQ<25>")
	)
	(segment
		(start 289.865308 -201.14133)
		(end 288.011616 -201.14133)
		(width 0.18288)
		(layer "In6.Cu")
		(net "M_C_CPU0_SB_DQ<25>")
	)
	(segment
		(start 290.174426 -200.832212)
		(end 289.865308 -201.14133)
		(width 0.18288)
		(layer "In6.Cu")
		(net "M_C_CPU0_SB_DQ<25>")
	)
	(segment
		(start 300.989746 -201.141838)
		(end 300.66488 -200.816972)
		(width 0.18288)
		(layer "In6.Cu")
		(net "M_C_CPU0_SB_DQ<25>")
	)
	(segment
		(start 305.763168 -202.39355)
		(end 305.580288 -202.57643)
		(width 0.18288)
		(layer "In6.Cu")
		(net "M_C_CPU0_SB_DQ<25>")
	)
	(segment
		(start 316.431676 -207.421988)
		(end 314.360052 -205.350364)
		(width 0.18288)
		(layer "In6.Cu")
		(net "M_C_CPU0_SB_DQ<25>")
	)
	(segment
		(start 309.250334 -202.981306)
		(end 309.250334 -203.28001)
		(width 0.18288)
		(layer "In6.Cu")
		(net "M_C_CPU0_SB_DQ<25>")
	)
	(segment
		(start 313.755532 -205.350364)
		(end 312.016394 -203.611226)
		(width 0.18288)
		(layer "In6.Cu")
		(net "M_C_CPU0_SB_DQ<25>")
	)
	(segment
		(start 334.488282 -226.506786)
		(end 334.477868 -226.512882)
		(width 0.088646)
		(layer "In6.Cu")
		(net "M_C_CPU0_SB_DQ<25>")
	)
	(segment
		(start 338.247482 -228.134672)
		(end 338.23275 -228.143308)
		(width 0.088646)
		(layer "In6.Cu")
		(net "M_C_CPU0_SB_DQ<25>")
	)
	(segment
		(start 302.376586 -201.141838)
		(end 302.05172 -200.816972)
		(width 0.18288)
		(layer "In6.Cu")
		(net "M_C_CPU0_SB_DQ<25>")
	)
	(segment
		(start 281.384756 -201.19213)
		(end 281.057096 -201.19213)
		(width 0.18288)
		(layer "In6.Cu")
		(net "M_C_CPU0_SB_DQ<25>")
	)
	(segment
		(start 305.580288 -202.57643)
		(end 305.255168 -202.57643)
		(width 0.18288)
		(layer "In6.Cu")
		(net "M_C_CPU0_SB_DQ<25>")
	)
	(segment
		(start 295.24579 -201.991722)
		(end 294.729662 -201.991722)
		(width 0.18288)
		(layer "In6.Cu")
		(net "M_C_CPU0_SB_DQ<25>")
	)
	(segment
		(start 330.642468 -224.415604)
		(end 330.41971 -224.415604)
		(width 0.088646)
		(layer "In6.Cu")
		(net "M_C_CPU0_SB_DQ<25>")
	)
	(segment
		(start 305.072288 -202.39355)
		(end 305.072288 -202.066906)
		(width 0.18288)
		(layer "In6.Cu")
		(net "M_C_CPU0_SB_DQ<25>")
	)
	(segment
		(start 334.871568 -226.511866)
		(end 334.862678 -226.506786)
		(width 0.088646)
		(layer "In6.Cu")
		(net "M_C_CPU0_SB_DQ<25>")
	)
	(segment
		(start 314.360052 -205.350364)
		(end 313.755532 -205.350364)
		(width 0.18288)
		(layer "In6.Cu")
		(net "M_C_CPU0_SB_DQ<25>")
	)
	(segment
		(start 301.683166 -200.816972)
		(end 301.3583 -201.141838)
		(width 0.18288)
		(layer "In6.Cu")
		(net "M_C_CPU0_SB_DQ<25>")
	)
	(segment
		(start 303.082706 -201.141838)
		(end 302.376586 -201.141838)
		(width 0.18288)
		(layer "In6.Cu")
		(net "M_C_CPU0_SB_DQ<25>")
	)
	(segment
		(start 337.307682 -228.134672)
		(end 337.29295 -228.143308)
		(width 0.088646)
		(layer "In6.Cu")
		(net "M_C_CPU0_SB_DQ<25>")
	)
	(segment
		(start 339.74913 -228.45903)
		(end 339.74913 -228.450394)
		(width 0.088646)
		(layer "In6.Cu")
		(net "M_C_CPU0_SB_DQ<25>")
	)
	(segment
		(start 287.318196 -200.842372)
		(end 287.019238 -201.14133)
		(width 0.18288)
		(layer "In6.Cu")
		(net "M_C_CPU0_SB_DQ<25>")
	)
	(segment
		(start 304.889408 -201.884026)
		(end 303.824894 -201.884026)
		(width 0.18288)
		(layer "In6.Cu")
		(net "M_C_CPU0_SB_DQ<25>")
	)
	(segment
		(start 307.685694 -202.798426)
		(end 306.771294 -201.884026)
		(width 0.18288)
		(layer "In6.Cu")
		(net "M_C_CPU0_SB_DQ<25>")
	)
	(segment
		(start 280.874216 -201.64806)
		(end 280.691336 -201.83094)
		(width 0.18288)
		(layer "In6.Cu")
		(net "M_C_CPU0_SB_DQ<25>")
	)
	(segment
		(start 282.115514 -201.99096)
		(end 281.955494 -201.83094)
		(width 0.18288)
		(layer "In6.Cu")
		(net "M_C_CPU0_SB_DQ<25>")
	)
	(segment
		(start 330.41971 -224.415604)
		(end 327.86574 -224.415604)
		(width 0.18288)
		(layer "In6.Cu")
		(net "M_C_CPU0_SB_DQ<25>")
	)
	(segment
		(start 281.057096 -201.19213)
		(end 280.874216 -201.37501)
		(width 0.18288)
		(layer "In6.Cu")
		(net "M_C_CPU0_SB_DQ<25>")
	)
	(segment
		(start 293.87927 -201.14133)
		(end 290.867846 -201.14133)
		(width 0.18288)
		(layer "In6.Cu")
		(net "M_C_CPU0_SB_DQ<25>")
	)
	(segment
		(start 281.567636 -201.64806)
		(end 281.567636 -201.37501)
		(width 0.18288)
		(layer "In6.Cu")
		(net "M_C_CPU0_SB_DQ<25>")
	)
	(segment
		(start 332.79588 -226.45624)
		(end 332.436978 -226.45624)
		(width 0.088646)
		(layer "In6.Cu")
		(net "M_C_CPU0_SB_DQ<25>")
	)
	(segment
		(start 327.86574 -224.415604)
		(end 326.84339 -223.393254)
		(width 0.18288)
		(layer "In6.Cu")
		(net "M_C_CPU0_SB_DQ<25>")
	)
	(segment
		(start 326.84339 -220.544644)
		(end 318.348868 -212.050122)
		(width 0.18288)
		(layer "In6.Cu")
		(net "M_C_CPU0_SB_DQ<25>")
	)
	(segment
		(start 300.66488 -200.816972)
		(end 300.296326 -200.816972)
		(width 0.18288)
		(layer "In6.Cu")
		(net "M_C_CPU0_SB_DQ<25>")
	)
	(segment
		(start 309.433214 -202.798426)
		(end 309.250334 -202.981306)
		(width 0.18288)
		(layer "In6.Cu")
		(net "M_C_CPU0_SB_DQ<25>")
	)
	(segment
		(start 308.742334 -203.46289)
		(end 308.559454 -203.28001)
		(width 0.18288)
		(layer "In6.Cu")
		(net "M_C_CPU0_SB_DQ<25>")
	)
	(segment
		(start 335.332578 -227.320602)
		(end 335.326482 -227.317046)
		(width 0.088646)
		(layer "In6.Cu")
		(net "M_C_CPU0_SB_DQ<25>")
	)
	(segment
		(start 318.348868 -212.050122)
		(end 316.431676 -207.421988)
		(width 0.18288)
		(layer "In6.Cu")
		(net "M_C_CPU0_SB_DQ<25>")
	)
	(segment
		(start 309.250334 -203.28001)
		(end 309.067454 -203.46289)
		(width 0.18288)
		(layer "In6.Cu")
		(net "M_C_CPU0_SB_DQ<25>")
	)
	(segment
		(start 336.367882 -228.134672)
		(end 336.357468 -228.140768)
		(width 0.088646)
		(layer "In6.Cu")
		(net "M_C_CPU0_SB_DQ<25>")
	)
	(segment
		(start 305.072288 -202.066906)
		(end 304.889408 -201.884026)
		(width 0.18288)
		(layer "In6.Cu")
		(net "M_C_CPU0_SB_DQ<25>")
	)
	(segment
		(start 280.691336 -201.83094)
		(end 280.402538 -201.83094)
		(width 0.18288)
		(layer "In6.Cu")
		(net "M_C_CPU0_SB_DQ<25>")
	)
	(segment
		(start 332.436978 -226.45624)
		(end 332.064868 -226.08413)
		(width 0.088646)
		(layer "In6.Cu")
		(net "M_C_CPU0_SB_DQ<25>")
	)
	(segment
		(start 332.064868 -225.838004)
		(end 330.642468 -224.415604)
		(width 0.088646)
		(layer "In6.Cu")
		(net "M_C_CPU0_SB_DQ<25>")
	)
	(segment
		(start 310.352694 -202.798426)
		(end 309.433214 -202.798426)
		(width 0.18288)
		(layer "In6.Cu")
		(net "M_C_CPU0_SB_DQ<25>")
	)
	(segment
		(start 287.019238 -201.14133)
		(end 286.22879 -201.14133)
		(width 0.18288)
		(layer "In6.Cu")
		(net "M_C_CPU0_SB_DQ<25>")
	)
	(segment
		(start 340.031832 -228.948488)
		(end 340.025736 -228.944932)
		(width 0.088646)
		(layer "In6.Cu")
		(net "M_C_CPU0_SB_DQ<25>")
	)
	(segment
		(start 326.84339 -223.393254)
		(end 326.84339 -220.544644)
		(width 0.18288)
		(layer "In6.Cu")
		(net "M_C_CPU0_SB_DQ<25>")
	)
	(segment
		(start 312.016394 -203.611226)
		(end 311.165494 -203.611226)
		(width 0.18288)
		(layer "In6.Cu")
		(net "M_C_CPU0_SB_DQ<25>")
	)
	(segment
		(start 281.750516 -201.83094)
		(end 281.567636 -201.64806)
		(width 0.18288)
		(layer "In6.Cu")
		(net "M_C_CPU0_SB_DQ<25>")
	)
	(segment
		(start 280.402538 -201.83094)
		(end 279.816814 -202.416664)
		(width 0.18288)
		(layer "In6.Cu")
		(net "M_C_CPU0_SB_DQ<25>")
	)
	(segment
		(start 308.376574 -202.798426)
		(end 307.685694 -202.798426)
		(width 0.18288)
		(layer "In6.Cu")
		(net "M_C_CPU0_SB_DQ<25>")
	)
	(segment
		(start 305.763168 -202.066906)
		(end 305.763168 -202.39355)
		(width 0.18288)
		(layer "In6.Cu")
		(net "M_C_CPU0_SB_DQ<25>")
	)
	(segment
		(start 309.067454 -203.46289)
		(end 308.742334 -203.46289)
		(width 0.18288)
		(layer "In6.Cu")
		(net "M_C_CPU0_SB_DQ<25>")
	)
	(segment
		(start 335.341468 -227.325682)
		(end 335.332578 -227.320602)
		(width 0.088646)
		(layer "In6.Cu")
		(net "M_C_CPU0_SB_DQ<25>")
	)
	(arc
		(start 340.597236 -228.948488)
		(mid 340.323037 -229.024323)
		(end 340.046564 -228.957124)
		(width 0.088646)
		(layer "In6.Cu")
		(net "M_C_CPU0_SB_DQ<25>")
	)
	(arc
		(start 333.548736 -226.506786)
		(mid 333.271923 -226.582656)
		(end 332.993492 -226.512882)
		(width 0.088646)
		(layer "In6.Cu")
		(net "M_C_CPU0_SB_DQ<25>")
	)
	(arc
		(start 341.537036 -228.948488)
		(mid 341.262837 -229.024323)
		(end 340.986364 -228.957124)
		(width 0.088646)
		(layer "In6.Cu")
		(net "M_C_CPU0_SB_DQ<25>")
	)
	(arc
		(start 335.802732 -228.134672)
		(mid 335.59766 -227.930993)
		(end 335.52003 -227.65258)
		(width 0.088646)
		(layer "In6.Cu")
		(net "M_C_CPU0_SB_DQ<25>")
	)
	(arc
		(start 336.357468 -228.140768)
		(mid 336.07929 -228.21046)
		(end 335.802732 -228.134672)
		(width 0.088646)
		(layer "In6.Cu")
		(net "M_C_CPU0_SB_DQ<25>")
	)
	(arc
		(start 335.05013 -226.831144)
		(mid 335.002451 -226.648244)
		(end 334.871568 -226.511866)
		(width 0.088646)
		(layer "In6.Cu")
		(net "M_C_CPU0_SB_DQ<25>")
	)
	(arc
		(start 339.74913 -228.450394)
		(mid 339.69686 -228.268029)
		(end 339.561932 -228.134672)
		(width 0.088646)
		(layer "In6.Cu")
		(net "M_C_CPU0_SB_DQ<25>")
	)
	(arc
		(start 342.476582 -228.948488)
		(mid 342.200023 -229.024231)
		(end 341.921846 -228.954584)
		(width 0.088646)
		(layer "In6.Cu")
		(net "M_C_CPU0_SB_DQ<25>")
	)
	(arc
		(start 337.29295 -228.143308)
		(mid 337.016509 -228.210474)
		(end 336.742278 -228.134672)
		(width 0.088646)
		(layer "In6.Cu")
		(net "M_C_CPU0_SB_DQ<25>")
	)
	(arc
		(start 339.561932 -228.134672)
		(mid 339.374734 -228.084529)
		(end 339.187536 -228.134672)
		(width 0.088646)
		(layer "In6.Cu")
		(net "M_C_CPU0_SB_DQ<25>")
	)
	(arc
		(start 334.477868 -226.512882)
		(mid 334.19969 -226.582605)
		(end 333.923132 -226.506786)
		(width 0.088646)
		(layer "In6.Cu")
		(net "M_C_CPU0_SB_DQ<25>")
	)
	(arc
		(start 343.13368 -228.45903)
		(mid 342.819398 -228.722914)
		(end 342.476582 -228.948488)
		(width 0.088646)
		(layer "In6.Cu")
		(net "M_C_CPU0_SB_DQ<25>")
	)
	(arc
		(start 334.862678 -226.506786)
		(mid 334.67548 -226.456643)
		(end 334.488282 -226.506786)
		(width 0.088646)
		(layer "In6.Cu")
		(net "M_C_CPU0_SB_DQ<25>")
	)
	(arc
		(start 335.326482 -227.317046)
		(mid 335.124069 -227.110633)
		(end 335.05013 -226.831144)
		(width 0.088646)
		(layer "In6.Cu")
		(net "M_C_CPU0_SB_DQ<25>")
	)
	(arc
		(start 332.993492 -226.512882)
		(mid 332.898648 -226.470731)
		(end 332.79588 -226.45624)
		(width 0.088646)
		(layer "In6.Cu")
		(net "M_C_CPU0_SB_DQ<25>")
	)
	(arc
		(start 340.971632 -228.948488)
		(mid 340.784434 -228.898345)
		(end 340.597236 -228.948488)
		(width 0.088646)
		(layer "In6.Cu")
		(net "M_C_CPU0_SB_DQ<25>")
	)
	(arc
		(start 335.52003 -227.64496)
		(mid 335.472351 -227.46206)
		(end 335.341468 -227.325682)
		(width 0.088646)
		(layer "In6.Cu")
		(net "M_C_CPU0_SB_DQ<25>")
	)
	(arc
		(start 340.025736 -228.944932)
		(mid 339.823149 -228.738581)
		(end 339.74913 -228.45903)
		(width 0.088646)
		(layer "In6.Cu")
		(net "M_C_CPU0_SB_DQ<25>")
	)
	(arc
		(start 337.682078 -228.134672)
		(mid 337.49488 -228.084529)
		(end 337.307682 -228.134672)
		(width 0.088646)
		(layer "In6.Cu")
		(net "M_C_CPU0_SB_DQ<25>")
	)
	(arc
		(start 333.923132 -226.506786)
		(mid 333.735934 -226.456643)
		(end 333.548736 -226.506786)
		(width 0.088646)
		(layer "In6.Cu")
		(net "M_C_CPU0_SB_DQ<25>")
	)
	(arc
		(start 338.621878 -228.134672)
		(mid 338.43468 -228.084529)
		(end 338.247482 -228.134672)
		(width 0.088646)
		(layer "In6.Cu")
		(net "M_C_CPU0_SB_DQ<25>")
	)
	(arc
		(start 338.23275 -228.143308)
		(mid 337.956309 -228.210474)
		(end 337.682078 -228.134672)
		(width 0.088646)
		(layer "In6.Cu")
		(net "M_C_CPU0_SB_DQ<25>")
	)
	(arc
		(start 341.911432 -228.948488)
		(mid 341.724234 -228.898345)
		(end 341.537036 -228.948488)
		(width 0.088646)
		(layer "In6.Cu")
		(net "M_C_CPU0_SB_DQ<25>")
	)
	(arc
		(start 336.742278 -228.134672)
		(mid 336.55508 -228.084529)
		(end 336.367882 -228.134672)
		(width 0.088646)
		(layer "In6.Cu")
		(net "M_C_CPU0_SB_DQ<25>")
	)
	(arc
		(start 339.177122 -228.140768)
		(mid 338.89869 -228.210582)
		(end 338.621878 -228.134672)
		(width 0.088646)
		(layer "In6.Cu")
		(net "M_C_CPU0_SB_DQ<25>")
	)
	(segment
		(start 343.60358 -229.808786)
		(end 343.603834 -229.808532)
		(width 0.20066)
		(layer "F.Cu")
		(net "M_C_CPU0_SB_DQ<24>")
	)
	(segment
		(start 274.152106 -203.691744)
		(end 274.143978 -203.683616)
		(width 0.101854)
		(layer "F.Cu")
		(net "M_C_CPU0_SB_DQ<24>")
	)
	(segment
		(start 273.37258 -203.893166)
		(end 273.37258 -204.182726)
		(width 0.20066)
		(layer "F.Cu")
		(net "M_C_CPU0_SB_DQ<24>")
	)
	(segment
		(start 343.603834 -229.808532)
		(end 343.603834 -229.272846)
		(width 0.20066)
		(layer "F.Cu")
		(net "M_C_CPU0_SB_DQ<24>")
	)
	(segment
		(start 279.816814 -204.116686)
		(end 278.711914 -204.116686)
		(width 0.20066)
		(layer "F.Cu")
		(net "M_C_CPU0_SB_DQ<24>")
	)
	(segment
		(start 273.37258 -204.182726)
		(end 273.19986 -204.355446)
		(width 0.20066)
		(layer "F.Cu")
		(net "M_C_CPU0_SB_DQ<24>")
	)
	(segment
		(start 278.711914 -204.116686)
		(end 277.342854 -204.116686)
		(width 0.20066)
		(layer "F.Cu")
		(net "M_C_CPU0_SB_DQ<24>")
	)
	(segment
		(start 276.469094 -203.691744)
		(end 274.40001 -203.691744)
		(width 0.1016)
		(layer "F.Cu")
		(net "M_C_CPU0_SB_DQ<24>")
	)
	(segment
		(start 272.502376 -204.116686)
		(end 271.168114 -204.116686)
		(width 0.20066)
		(layer "F.Cu")
		(net "M_C_CPU0_SB_DQ<24>")
	)
	(segment
		(start 274.143978 -203.683616)
		(end 273.58213 -203.683616)
		(width 0.20066)
		(layer "F.Cu")
		(net "M_C_CPU0_SB_DQ<24>")
	)
	(segment
		(start 276.917912 -203.691744)
		(end 276.469094 -203.691744)
		(width 0.20066)
		(layer "F.Cu")
		(net "M_C_CPU0_SB_DQ<24>")
	)
	(segment
		(start 274.40001 -203.691744)
		(end 274.152106 -203.691744)
		(width 0.101854)
		(layer "F.Cu")
		(net "M_C_CPU0_SB_DQ<24>")
	)
	(segment
		(start 272.741136 -204.355446)
		(end 272.502376 -204.116686)
		(width 0.20066)
		(layer "F.Cu")
		(net "M_C_CPU0_SB_DQ<24>")
	)
	(segment
		(start 277.342854 -204.116686)
		(end 276.917912 -203.691744)
		(width 0.20066)
		(layer "F.Cu")
		(net "M_C_CPU0_SB_DQ<24>")
	)
	(segment
		(start 273.19986 -204.355446)
		(end 272.741136 -204.355446)
		(width 0.20066)
		(layer "F.Cu")
		(net "M_C_CPU0_SB_DQ<24>")
	)
	(segment
		(start 273.58213 -203.683616)
		(end 273.37258 -203.893166)
		(width 0.20066)
		(layer "F.Cu")
		(net "M_C_CPU0_SB_DQ<24>")
	)
	(segment
		(start 293.944294 -202.156822)
		(end 292.55339 -202.156822)
		(width 0.18288)
		(layer "In6.Cu")
		(net "M_C_CPU0_SB_DQ<24>")
	)
	(segment
		(start 297.779948 -201.683112)
		(end 297.471338 -201.991722)
		(width 0.18288)
		(layer "In6.Cu")
		(net "M_C_CPU0_SB_DQ<24>")
	)
	(segment
		(start 280.337768 -203.595732)
		(end 279.816814 -204.116686)
		(width 0.18288)
		(layer "In6.Cu")
		(net "M_C_CPU0_SB_DQ<24>")
	)
	(segment
		(start 280.522172 -202.840844)
		(end 280.337768 -203.025248)
		(width 0.18288)
		(layer "In6.Cu")
		(net "M_C_CPU0_SB_DQ<24>")
	)
	(segment
		(start 292.55339 -202.156822)
		(end 292.280594 -201.884026)
		(width 0.18288)
		(layer "In6.Cu")
		(net "M_C_CPU0_SB_DQ<24>")
	)
	(segment
		(start 281.790648 -203.023724)
		(end 281.790648 -203.452984)
		(width 0.18288)
		(layer "In6.Cu")
		(net "M_C_CPU0_SB_DQ<24>")
	)
	(segment
		(start 342.861392 -229.591108)
		(end 342.850978 -229.597204)
		(width 0.088646)
		(layer "In6.Cu")
		(net "M_C_CPU0_SB_DQ<24>")
	)
	(segment
		(start 298.473368 -201.991722)
		(end 298.164758 -201.683112)
		(width 0.18288)
		(layer "In6.Cu")
		(net "M_C_CPU0_SB_DQ<24>")
	)
	(segment
		(start 284.652974 -202.417426)
		(end 284.229556 -202.840844)
		(width 0.18288)
		(layer "In6.Cu")
		(net "M_C_CPU0_SB_DQ<24>")
	)
	(segment
		(start 327.659492 -224.913444)
		(end 326.34555 -223.599502)
		(width 0.18288)
		(layer "In6.Cu")
		(net "M_C_CPU0_SB_DQ<24>")
	)
	(segment
		(start 281.097228 -203.023724)
		(end 280.914348 -202.840844)
		(width 0.18288)
		(layer "In6.Cu")
		(net "M_C_CPU0_SB_DQ<24>")
	)
	(segment
		(start 285.91764 -202.417426)
		(end 284.652974 -202.417426)
		(width 0.18288)
		(layer "In6.Cu")
		(net "M_C_CPU0_SB_DQ<24>")
	)
	(segment
		(start 281.607768 -203.635864)
		(end 281.280108 -203.635864)
		(width 0.18288)
		(layer "In6.Cu")
		(net "M_C_CPU0_SB_DQ<24>")
	)
	(segment
		(start 299.544486 -201.991722)
		(end 298.473368 -201.991722)
		(width 0.18288)
		(layer "In6.Cu")
		(net "M_C_CPU0_SB_DQ<24>")
	)
	(segment
		(start 284.229556 -202.840844)
		(end 281.973528 -202.840844)
		(width 0.18288)
		(layer "In6.Cu")
		(net "M_C_CPU0_SB_DQ<24>")
	)
	(segment
		(start 340.986364 -229.588568)
		(end 340.971632 -229.597204)
		(width 0.088646)
		(layer "In6.Cu")
		(net "M_C_CPU0_SB_DQ<24>")
	)
	(segment
		(start 281.097228 -203.452984)
		(end 281.097228 -203.023724)
		(width 0.18288)
		(layer "In6.Cu")
		(net "M_C_CPU0_SB_DQ<24>")
	)
	(segment
		(start 281.790648 -203.452984)
		(end 281.607768 -203.635864)
		(width 0.18288)
		(layer "In6.Cu")
		(net "M_C_CPU0_SB_DQ<24>")
	)
	(segment
		(start 301.624746 -202.343766)
		(end 301.28337 -202.343766)
		(width 0.18288)
		(layer "In6.Cu")
		(net "M_C_CPU0_SB_DQ<24>")
	)
	(segment
		(start 336.367882 -228.783388)
		(end 336.357468 -228.777292)
		(width 0.088646)
		(layer "In6.Cu")
		(net "M_C_CPU0_SB_DQ<24>")
	)
	(segment
		(start 295.961562 -201.991722)
		(end 295.111424 -202.84186)
		(width 0.18288)
		(layer "In6.Cu")
		(net "M_C_CPU0_SB_DQ<24>")
	)
	(segment
		(start 280.914348 -202.840844)
		(end 280.522172 -202.840844)
		(width 0.18288)
		(layer "In6.Cu")
		(net "M_C_CPU0_SB_DQ<24>")
	)
	(segment
		(start 338.247482 -228.783388)
		(end 338.23275 -228.774752)
		(width 0.088646)
		(layer "In6.Cu")
		(net "M_C_CPU0_SB_DQ<24>")
	)
	(segment
		(start 288.96183 -201.884026)
		(end 288.765742 -202.080114)
		(width 0.18288)
		(layer "In6.Cu")
		(net "M_C_CPU0_SB_DQ<24>")
	)
	(segment
		(start 334.488282 -227.155502)
		(end 334.477868 -227.149406)
		(width 0.088646)
		(layer "In6.Cu")
		(net "M_C_CPU0_SB_DQ<24>")
	)
	(segment
		(start 331.820774 -226.385882)
		(end 331.820774 -226.07778)
		(width 0.088646)
		(layer "In6.Cu")
		(net "M_C_CPU0_SB_DQ<24>")
	)
	(segment
		(start 302.81499 -201.991722)
		(end 301.97679 -201.991722)
		(width 0.18288)
		(layer "In6.Cu")
		(net "M_C_CPU0_SB_DQ<24>")
	)
	(segment
		(start 294.629332 -202.84186)
		(end 293.944294 -202.156822)
		(width 0.18288)
		(layer "In6.Cu")
		(net "M_C_CPU0_SB_DQ<24>")
	)
	(segment
		(start 339.657436 -229.597204)
		(end 339.648546 -229.592124)
		(width 0.088646)
		(layer "In6.Cu")
		(net "M_C_CPU0_SB_DQ<24>")
	)
	(segment
		(start 306.974494 -203.103226)
		(end 303.926494 -203.103226)
		(width 0.18288)
		(layer "In6.Cu")
		(net "M_C_CPU0_SB_DQ<24>")
	)
	(segment
		(start 326.34555 -223.599502)
		(end 326.34555 -220.809312)
		(width 0.18288)
		(layer "In6.Cu")
		(net "M_C_CPU0_SB_DQ<24>")
	)
	(segment
		(start 307.831998 -203.96073)
		(end 306.974494 -203.103226)
		(width 0.18288)
		(layer "In6.Cu")
		(net "M_C_CPU0_SB_DQ<24>")
	)
	(segment
		(start 316.060328 -207.860392)
		(end 314.687204 -206.487268)
		(width 0.18288)
		(layer "In6.Cu")
		(net "M_C_CPU0_SB_DQ<24>")
	)
	(segment
		(start 334.494378 -227.159058)
		(end 334.488282 -227.155502)
		(width 0.088646)
		(layer "In6.Cu")
		(net "M_C_CPU0_SB_DQ<24>")
	)
	(segment
		(start 314.026804 -206.487268)
		(end 312.319162 -204.779626)
		(width 0.18288)
		(layer "In6.Cu")
		(net "M_C_CPU0_SB_DQ<24>")
	)
	(segment
		(start 332.993492 -227.149406)
		(end 332.983078 -227.155502)
		(width 0.088646)
		(layer "In6.Cu")
		(net "M_C_CPU0_SB_DQ<24>")
	)
	(segment
		(start 341.921846 -229.591108)
		(end 341.911432 -229.597204)
		(width 0.088646)
		(layer "In6.Cu")
		(net "M_C_CPU0_SB_DQ<24>")
	)
	(segment
		(start 317.943484 -212.407246)
		(end 316.060328 -207.860392)
		(width 0.18288)
		(layer "In6.Cu")
		(net "M_C_CPU0_SB_DQ<24>")
	)
	(segment
		(start 331.820774 -226.07778)
		(end 330.656438 -224.913444)
		(width 0.088646)
		(layer "In6.Cu")
		(net "M_C_CPU0_SB_DQ<24>")
	)
	(segment
		(start 334.770984 -227.660454)
		(end 334.770984 -227.64496)
		(width 0.088646)
		(layer "In6.Cu")
		(net "M_C_CPU0_SB_DQ<24>")
	)
	(segment
		(start 339.187536 -228.783388)
		(end 339.177122 -228.777292)
		(width 0.088646)
		(layer "In6.Cu")
		(net "M_C_CPU0_SB_DQ<24>")
	)
	(segment
		(start 280.337768 -203.025248)
		(end 280.337768 -203.595732)
		(width 0.18288)
		(layer "In6.Cu")
		(net "M_C_CPU0_SB_DQ<24>")
	)
	(segment
		(start 332.530958 -227.096066)
		(end 331.820774 -226.385882)
		(width 0.088646)
		(layer "In6.Cu")
		(net "M_C_CPU0_SB_DQ<24>")
	)
	(segment
		(start 311.444894 -204.779626)
		(end 310.625998 -203.96073)
		(width 0.18288)
		(layer "In6.Cu")
		(net "M_C_CPU0_SB_DQ<24>")
	)
	(segment
		(start 312.319162 -204.779626)
		(end 311.444894 -204.779626)
		(width 0.18288)
		(layer "In6.Cu")
		(net "M_C_CPU0_SB_DQ<24>")
	)
	(segment
		(start 288.765742 -202.080114)
		(end 286.254952 -202.080114)
		(width 0.18288)
		(layer "In6.Cu")
		(net "M_C_CPU0_SB_DQ<24>")
	)
	(segment
		(start 301.28337 -202.343766)
		(end 300.931326 -201.991722)
		(width 0.18288)
		(layer "In6.Cu")
		(net "M_C_CPU0_SB_DQ<24>")
	)
	(segment
		(start 292.280594 -201.884026)
		(end 288.96183 -201.884026)
		(width 0.18288)
		(layer "In6.Cu")
		(net "M_C_CPU0_SB_DQ<24>")
	)
	(segment
		(start 337.307682 -228.783388)
		(end 337.29295 -228.774752)
		(width 0.088646)
		(layer "In6.Cu")
		(net "M_C_CPU0_SB_DQ<24>")
	)
	(segment
		(start 299.89653 -202.343766)
		(end 299.544486 -201.991722)
		(width 0.18288)
		(layer "In6.Cu")
		(net "M_C_CPU0_SB_DQ<24>")
	)
	(segment
		(start 300.237906 -202.343766)
		(end 299.89653 -202.343766)
		(width 0.18288)
		(layer "In6.Cu")
		(net "M_C_CPU0_SB_DQ<24>")
	)
	(segment
		(start 303.926494 -203.103226)
		(end 302.81499 -201.991722)
		(width 0.18288)
		(layer "In6.Cu")
		(net "M_C_CPU0_SB_DQ<24>")
	)
	(segment
		(start 326.34555 -220.809312)
		(end 317.943484 -212.407246)
		(width 0.18288)
		(layer "In6.Cu")
		(net "M_C_CPU0_SB_DQ<24>")
	)
	(segment
		(start 298.164758 -201.683112)
		(end 297.779948 -201.683112)
		(width 0.18288)
		(layer "In6.Cu")
		(net "M_C_CPU0_SB_DQ<24>")
	)
	(segment
		(start 330.41971 -224.913444)
		(end 327.659492 -224.913444)
		(width 0.18288)
		(layer "In6.Cu")
		(net "M_C_CPU0_SB_DQ<24>")
	)
	(segment
		(start 310.625998 -203.96073)
		(end 307.831998 -203.96073)
		(width 0.18288)
		(layer "In6.Cu")
		(net "M_C_CPU0_SB_DQ<24>")
	)
	(segment
		(start 300.931326 -201.991722)
		(end 300.58995 -201.991722)
		(width 0.18288)
		(layer "In6.Cu")
		(net "M_C_CPU0_SB_DQ<24>")
	)
	(segment
		(start 301.97679 -201.991722)
		(end 301.624746 -202.343766)
		(width 0.18288)
		(layer "In6.Cu")
		(net "M_C_CPU0_SB_DQ<24>")
	)
	(segment
		(start 314.687204 -206.487268)
		(end 314.026804 -206.487268)
		(width 0.18288)
		(layer "In6.Cu")
		(net "M_C_CPU0_SB_DQ<24>")
	)
	(segment
		(start 295.111424 -202.84186)
		(end 294.629332 -202.84186)
		(width 0.18288)
		(layer "In6.Cu")
		(net "M_C_CPU0_SB_DQ<24>")
	)
	(segment
		(start 340.046564 -229.588568)
		(end 340.031832 -229.597204)
		(width 0.088646)
		(layer "In6.Cu")
		(net "M_C_CPU0_SB_DQ<24>")
	)
	(segment
		(start 330.656438 -224.913444)
		(end 330.41971 -224.913444)
		(width 0.088646)
		(layer "In6.Cu")
		(net "M_C_CPU0_SB_DQ<24>")
	)
	(segment
		(start 332.617318 -227.160328)
		(end 332.608936 -227.155502)
		(width 0.088646)
		(layer "In6.Cu")
		(net "M_C_CPU0_SB_DQ<24>")
	)
	(segment
		(start 281.280108 -203.635864)
		(end 281.097228 -203.452984)
		(width 0.18288)
		(layer "In6.Cu")
		(net "M_C_CPU0_SB_DQ<24>")
	)
	(segment
		(start 297.471338 -201.991722)
		(end 295.961562 -201.991722)
		(width 0.18288)
		(layer "In6.Cu")
		(net "M_C_CPU0_SB_DQ<24>")
	)
	(segment
		(start 300.58995 -201.991722)
		(end 300.237906 -202.343766)
		(width 0.18288)
		(layer "In6.Cu")
		(net "M_C_CPU0_SB_DQ<24>")
	)
	(segment
		(start 335.428336 -228.783388)
		(end 335.419446 -228.778308)
		(width 0.088646)
		(layer "In6.Cu")
		(net "M_C_CPU0_SB_DQ<24>")
	)
	(segment
		(start 281.973528 -202.840844)
		(end 281.790648 -203.023724)
		(width 0.18288)
		(layer "In6.Cu")
		(net "M_C_CPU0_SB_DQ<24>")
	)
	(segment
		(start 339.469984 -229.272846)
		(end 339.469984 -229.26294)
		(width 0.088646)
		(layer "In6.Cu")
		(net "M_C_CPU0_SB_DQ<24>")
	)
	(segment
		(start 335.240884 -228.45903)
		(end 335.24063 -228.444806)
		(width 0.088646)
		(layer "In6.Cu")
		(net "M_C_CPU0_SB_DQ<24>")
	)
	(segment
		(start 286.254952 -202.080114)
		(end 285.91764 -202.417426)
		(width 0.18288)
		(layer "In6.Cu")
		(net "M_C_CPU0_SB_DQ<24>")
	)
	(arc
		(start 335.419446 -228.778308)
		(mid 335.288532 -228.641948)
		(end 335.240884 -228.45903)
		(width 0.088646)
		(layer "In6.Cu")
		(net "M_C_CPU0_SB_DQ<24>")
	)
	(arc
		(start 334.770984 -227.64496)
		(mid 334.696993 -227.365394)
		(end 334.494378 -227.159058)
		(width 0.088646)
		(layer "In6.Cu")
		(net "M_C_CPU0_SB_DQ<24>")
	)
	(arc
		(start 340.597236 -229.597204)
		(mid 340.323037 -229.521369)
		(end 340.046564 -229.588568)
		(width 0.088646)
		(layer "In6.Cu")
		(net "M_C_CPU0_SB_DQ<24>")
	)
	(arc
		(start 332.608936 -227.155502)
		(mid 332.568007 -227.128331)
		(end 332.530958 -227.096066)
		(width 0.088646)
		(layer "In6.Cu")
		(net "M_C_CPU0_SB_DQ<24>")
	)
	(arc
		(start 340.031832 -229.597204)
		(mid 339.844634 -229.647347)
		(end 339.657436 -229.597204)
		(width 0.088646)
		(layer "In6.Cu")
		(net "M_C_CPU0_SB_DQ<24>")
	)
	(arc
		(start 332.983078 -227.155502)
		(mid 332.800827 -227.205613)
		(end 332.617318 -227.160328)
		(width 0.088646)
		(layer "In6.Cu")
		(net "M_C_CPU0_SB_DQ<24>")
	)
	(arc
		(start 339.469984 -229.26294)
		(mid 339.391873 -228.985991)
		(end 339.187536 -228.783388)
		(width 0.088646)
		(layer "In6.Cu")
		(net "M_C_CPU0_SB_DQ<24>")
	)
	(arc
		(start 341.911432 -229.597204)
		(mid 341.724234 -229.647347)
		(end 341.537036 -229.597204)
		(width 0.088646)
		(layer "In6.Cu")
		(net "M_C_CPU0_SB_DQ<24>")
	)
	(arc
		(start 336.357468 -228.777292)
		(mid 336.07929 -228.707569)
		(end 335.802732 -228.783388)
		(width 0.088646)
		(layer "In6.Cu")
		(net "M_C_CPU0_SB_DQ<24>")
	)
	(arc
		(start 333.923132 -227.155502)
		(mid 333.735934 -227.205645)
		(end 333.548736 -227.155502)
		(width 0.088646)
		(layer "In6.Cu")
		(net "M_C_CPU0_SB_DQ<24>")
	)
	(arc
		(start 333.548736 -227.155502)
		(mid 333.271923 -227.079632)
		(end 332.993492 -227.149406)
		(width 0.088646)
		(layer "In6.Cu")
		(net "M_C_CPU0_SB_DQ<24>")
	)
	(arc
		(start 338.23275 -228.774752)
		(mid 337.956275 -228.707432)
		(end 337.682078 -228.783388)
		(width 0.088646)
		(layer "In6.Cu")
		(net "M_C_CPU0_SB_DQ<24>")
	)
	(arc
		(start 339.177122 -228.777292)
		(mid 338.89869 -228.707446)
		(end 338.621878 -228.783388)
		(width 0.088646)
		(layer "In6.Cu")
		(net "M_C_CPU0_SB_DQ<24>")
	)
	(arc
		(start 338.621878 -228.783388)
		(mid 338.43468 -228.833531)
		(end 338.247482 -228.783388)
		(width 0.088646)
		(layer "In6.Cu")
		(net "M_C_CPU0_SB_DQ<24>")
	)
	(arc
		(start 343.603834 -229.272846)
		(mid 343.222685 -229.408818)
		(end 342.861392 -229.591108)
		(width 0.088646)
		(layer "In6.Cu")
		(net "M_C_CPU0_SB_DQ<24>")
	)
	(arc
		(start 342.850978 -229.597204)
		(mid 342.66378 -229.647347)
		(end 342.476582 -229.597204)
		(width 0.088646)
		(layer "In6.Cu")
		(net "M_C_CPU0_SB_DQ<24>")
	)
	(arc
		(start 339.648546 -229.592124)
		(mid 339.517632 -229.455764)
		(end 339.469984 -229.272846)
		(width 0.088646)
		(layer "In6.Cu")
		(net "M_C_CPU0_SB_DQ<24>")
	)
	(arc
		(start 334.958182 -227.969572)
		(mid 334.824854 -227.839072)
		(end 334.770984 -227.660454)
		(width 0.088646)
		(layer "In6.Cu")
		(net "M_C_CPU0_SB_DQ<24>")
	)
	(arc
		(start 342.476582 -229.597204)
		(mid 342.200023 -229.521461)
		(end 341.921846 -229.591108)
		(width 0.088646)
		(layer "In6.Cu")
		(net "M_C_CPU0_SB_DQ<24>")
	)
	(arc
		(start 337.682078 -228.783388)
		(mid 337.49488 -228.833531)
		(end 337.307682 -228.783388)
		(width 0.088646)
		(layer "In6.Cu")
		(net "M_C_CPU0_SB_DQ<24>")
	)
	(arc
		(start 335.24063 -228.444806)
		(mid 335.161499 -228.17027)
		(end 334.958182 -227.969572)
		(width 0.088646)
		(layer "In6.Cu")
		(net "M_C_CPU0_SB_DQ<24>")
	)
	(arc
		(start 336.742278 -228.783388)
		(mid 336.55508 -228.833531)
		(end 336.367882 -228.783388)
		(width 0.088646)
		(layer "In6.Cu")
		(net "M_C_CPU0_SB_DQ<24>")
	)
	(arc
		(start 340.971632 -229.597204)
		(mid 340.784434 -229.647347)
		(end 340.597236 -229.597204)
		(width 0.088646)
		(layer "In6.Cu")
		(net "M_C_CPU0_SB_DQ<24>")
	)
	(arc
		(start 337.29295 -228.774752)
		(mid 337.016475 -228.707432)
		(end 336.742278 -228.783388)
		(width 0.088646)
		(layer "In6.Cu")
		(net "M_C_CPU0_SB_DQ<24>")
	)
	(arc
		(start 335.802732 -228.783388)
		(mid 335.615534 -228.833531)
		(end 335.428336 -228.783388)
		(width 0.088646)
		(layer "In6.Cu")
		(net "M_C_CPU0_SB_DQ<24>")
	)
	(arc
		(start 341.537036 -229.597204)
		(mid 341.262837 -229.521369)
		(end 340.986364 -229.588568)
		(width 0.088646)
		(layer "In6.Cu")
		(net "M_C_CPU0_SB_DQ<24>")
	)
	(arc
		(start 334.477868 -227.149406)
		(mid 334.19969 -227.079683)
		(end 333.923132 -227.155502)
		(width 0.088646)
		(layer "In6.Cu")
		(net "M_C_CPU0_SB_DQ<24>")
	)
	(segment
		(start 280.606246 -205.090776)
		(end 280.606246 -205.242414)
		(width 0.20066)
		(layer "F.Cu")
		(net "M_C_CPU0_SB_DQ<23>")
	)
	(segment
		(start 280.457148 -205.391512)
		(end 279.912826 -205.391512)
		(width 0.20066)
		(layer "F.Cu")
		(net "M_C_CPU0_SB_DQ<23>")
	)
	(segment
		(start 280.606246 -205.242414)
		(end 280.457148 -205.391512)
		(width 0.20066)
		(layer "F.Cu")
		(net "M_C_CPU0_SB_DQ<23>")
	)
	(segment
		(start 277.839932 -205.391512)
		(end 277.601934 -205.391512)
		(width 0.101854)
		(layer "F.Cu")
		(net "M_C_CPU0_SB_DQ<23>")
	)
	(segment
		(start 279.912826 -205.391512)
		(end 277.839932 -205.391512)
		(width 0.1016)
		(layer "F.Cu")
		(net "M_C_CPU0_SB_DQ<23>")
	)
	(segment
		(start 281.129994 -204.962252)
		(end 280.73477 -204.962252)
		(width 0.20066)
		(layer "F.Cu")
		(net "M_C_CPU0_SB_DQ<23>")
	)
	(segment
		(start 341.254334 -228.99497)
		(end 341.25408 -228.994716)
		(width 0.20066)
		(layer "F.Cu")
		(net "M_C_CPU0_SB_DQ<23>")
	)
	(segment
		(start 277.091394 -205.092554)
		(end 276.96541 -204.96657)
		(width 0.20066)
		(layer "F.Cu")
		(net "M_C_CPU0_SB_DQ<23>")
	)
	(segment
		(start 282.811982 -204.96657)
		(end 281.99588 -204.96657)
		(width 0.20066)
		(layer "F.Cu")
		(net "M_C_CPU0_SB_DQ<23>")
	)
	(segment
		(start 277.58771 -205.405736)
		(end 277.233888 -205.405736)
		(width 0.20066)
		(layer "F.Cu")
		(net "M_C_CPU0_SB_DQ<23>")
	)
	(segment
		(start 283.916882 -204.96657)
		(end 282.811982 -204.96657)
		(width 0.20066)
		(layer "F.Cu")
		(net "M_C_CPU0_SB_DQ<23>")
	)
	(segment
		(start 341.25408 -228.994716)
		(end 341.25408 -228.45903)
		(width 0.20066)
		(layer "F.Cu")
		(net "M_C_CPU0_SB_DQ<23>")
	)
	(segment
		(start 281.99588 -204.96657)
		(end 281.788362 -205.174088)
		(width 0.20066)
		(layer "F.Cu")
		(net "M_C_CPU0_SB_DQ<23>")
	)
	(segment
		(start 277.601934 -205.391512)
		(end 277.58771 -205.405736)
		(width 0.101854)
		(layer "F.Cu")
		(net "M_C_CPU0_SB_DQ<23>")
	)
	(segment
		(start 277.091394 -205.263242)
		(end 277.091394 -205.092554)
		(width 0.20066)
		(layer "F.Cu")
		(net "M_C_CPU0_SB_DQ<23>")
	)
	(segment
		(start 281.788362 -205.174088)
		(end 281.34183 -205.174088)
		(width 0.20066)
		(layer "F.Cu")
		(net "M_C_CPU0_SB_DQ<23>")
	)
	(segment
		(start 277.233888 -205.405736)
		(end 277.091394 -205.263242)
		(width 0.20066)
		(layer "F.Cu")
		(net "M_C_CPU0_SB_DQ<23>")
	)
	(segment
		(start 281.34183 -205.174088)
		(end 281.129994 -204.962252)
		(width 0.20066)
		(layer "F.Cu")
		(net "M_C_CPU0_SB_DQ<23>")
	)
	(segment
		(start 276.96541 -204.96657)
		(end 275.268182 -204.96657)
		(width 0.20066)
		(layer "F.Cu")
		(net "M_C_CPU0_SB_DQ<23>")
	)
	(segment
		(start 280.73477 -204.962252)
		(end 280.606246 -205.090776)
		(width 0.20066)
		(layer "F.Cu")
		(net "M_C_CPU0_SB_DQ<23>")
	)
	(segment
		(start 341.25408 -228.45903)
		(end 340.941152 -228.45903)
		(width 0.088646)
		(layer "In4.Cu")
		(net "M_C_CPU0_SB_DQ<23>")
	)
	(segment
		(start 338.166964 -227.960682)
		(end 338.152232 -227.969318)
		(width 0.088646)
		(layer "In4.Cu")
		(net "M_C_CPU0_SB_DQ<23>")
	)
	(segment
		(start 294.06088 -205.921102)
		(end 292.768528 -205.921102)
		(width 0.18288)
		(layer "In4.Cu")
		(net "M_C_CPU0_SB_DQ<23>")
	)
	(segment
		(start 292.079934 -205.232508)
		(end 288.297366 -205.232508)
		(width 0.18288)
		(layer "In4.Cu")
		(net "M_C_CPU0_SB_DQ<23>")
	)
	(segment
		(start 286.009842 -203.897738)
		(end 286.009842 -205.410816)
		(width 0.18288)
		(layer "In4.Cu")
		(net "M_C_CPU0_SB_DQ<23>")
	)
	(segment
		(start 331.877416 -227.593144)
		(end 331.877416 -227.358194)
		(width 0.088646)
		(layer "In4.Cu")
		(net "M_C_CPU0_SB_DQ<23>")
	)
	(segment
		(start 337.227164 -227.960682)
		(end 337.212432 -227.969318)
		(width 0.088646)
		(layer "In4.Cu")
		(net "M_C_CPU0_SB_DQ<23>")
	)
	(segment
		(start 331.877416 -227.358194)
		(end 330.880974 -226.361752)
		(width 0.088646)
		(layer "In4.Cu")
		(net "M_C_CPU0_SB_DQ<23>")
	)
	(segment
		(start 286.700722 -205.410816)
		(end 286.700722 -203.897738)
		(width 0.18288)
		(layer "In4.Cu")
		(net "M_C_CPU0_SB_DQ<23>")
	)
	(segment
		(start 288.297366 -205.232508)
		(end 287.936178 -205.593696)
		(width 0.18288)
		(layer "In4.Cu")
		(net "M_C_CPU0_SB_DQ<23>")
	)
	(segment
		(start 336.287364 -227.960682)
		(end 336.272632 -227.969318)
		(width 0.088646)
		(layer "In4.Cu")
		(net "M_C_CPU0_SB_DQ<23>")
	)
	(segment
		(start 306.80279 -206.372714)
		(end 303.63414 -206.372714)
		(width 0.18288)
		(layer "In4.Cu")
		(net "M_C_CPU0_SB_DQ<23>")
	)
	(segment
		(start 307.073808 -206.101696)
		(end 306.80279 -206.372714)
		(width 0.18288)
		(layer "In4.Cu")
		(net "M_C_CPU0_SB_DQ<23>")
	)
	(segment
		(start 330.648564 -226.361752)
		(end 326.92594 -226.361752)
		(width 0.18288)
		(layer "In4.Cu")
		(net "M_C_CPU0_SB_DQ<23>")
	)
	(segment
		(start 321.299332 -220.735144)
		(end 316.291976 -208.646776)
		(width 0.18288)
		(layer "In4.Cu")
		(net "M_C_CPU0_SB_DQ<23>")
	)
	(segment
		(start 287.936178 -205.593696)
		(end 286.883602 -205.593696)
		(width 0.18288)
		(layer "In4.Cu")
		(net "M_C_CPU0_SB_DQ<23>")
	)
	(segment
		(start 286.700722 -203.897738)
		(end 286.517842 -203.714858)
		(width 0.18288)
		(layer "In4.Cu")
		(net "M_C_CPU0_SB_DQ<23>")
	)
	(segment
		(start 285.162498 -205.593696)
		(end 284.35554 -204.786738)
		(width 0.18288)
		(layer "In4.Cu")
		(net "M_C_CPU0_SB_DQ<23>")
	)
	(segment
		(start 299.401992 -205.391258)
		(end 298.909486 -205.391258)
		(width 0.18288)
		(layer "In4.Cu")
		(net "M_C_CPU0_SB_DQ<23>")
	)
	(segment
		(start 292.768528 -205.921102)
		(end 292.079934 -205.232508)
		(width 0.18288)
		(layer "In4.Cu")
		(net "M_C_CPU0_SB_DQ<23>")
	)
	(segment
		(start 286.192722 -203.714858)
		(end 286.009842 -203.897738)
		(width 0.18288)
		(layer "In4.Cu")
		(net "M_C_CPU0_SB_DQ<23>")
	)
	(segment
		(start 298.909486 -205.391258)
		(end 298.620688 -205.510892)
		(width 0.18288)
		(layer "In4.Cu")
		(net "M_C_CPU0_SB_DQ<23>")
	)
	(segment
		(start 286.883602 -205.593696)
		(end 286.700722 -205.410816)
		(width 0.18288)
		(layer "In4.Cu")
		(net "M_C_CPU0_SB_DQ<23>")
	)
	(segment
		(start 298.108116 -205.737206)
		(end 297.603418 -206.241904)
		(width 0.18288)
		(layer "In4.Cu")
		(net "M_C_CPU0_SB_DQ<23>")
	)
	(segment
		(start 314.207398 -206.562198)
		(end 311.677812 -206.562198)
		(width 0.18288)
		(layer "In4.Cu")
		(net "M_C_CPU0_SB_DQ<23>")
	)
	(segment
		(start 326.92594 -226.361752)
		(end 321.299332 -220.735144)
		(width 0.18288)
		(layer "In4.Cu")
		(net "M_C_CPU0_SB_DQ<23>")
	)
	(segment
		(start 298.394374 -205.737206)
		(end 298.108116 -205.737206)
		(width 0.18288)
		(layer "In4.Cu")
		(net "M_C_CPU0_SB_DQ<23>")
	)
	(segment
		(start 334.958182 -227.969318)
		(end 334.947768 -227.963222)
		(width 0.088646)
		(layer "In4.Cu")
		(net "M_C_CPU0_SB_DQ<23>")
	)
	(segment
		(start 311.21731 -206.101696)
		(end 307.073808 -206.101696)
		(width 0.18288)
		(layer "In4.Cu")
		(net "M_C_CPU0_SB_DQ<23>")
	)
	(segment
		(start 286.517842 -203.714858)
		(end 286.192722 -203.714858)
		(width 0.18288)
		(layer "In4.Cu")
		(net "M_C_CPU0_SB_DQ<23>")
	)
	(segment
		(start 332.259686 -227.975414)
		(end 331.877416 -227.593144)
		(width 0.088646)
		(layer "In4.Cu")
		(net "M_C_CPU0_SB_DQ<23>")
	)
	(segment
		(start 316.291976 -208.646776)
		(end 314.207398 -206.562198)
		(width 0.18288)
		(layer "In4.Cu")
		(net "M_C_CPU0_SB_DQ<23>")
	)
	(segment
		(start 303.63414 -206.372714)
		(end 302.968152 -205.706726)
		(width 0.18288)
		(layer "In4.Cu")
		(net "M_C_CPU0_SB_DQ<23>")
	)
	(segment
		(start 330.880974 -226.361752)
		(end 330.648564 -226.361752)
		(width 0.088646)
		(layer "In4.Cu")
		(net "M_C_CPU0_SB_DQ<23>")
	)
	(segment
		(start 311.677812 -206.562198)
		(end 311.21731 -206.101696)
		(width 0.18288)
		(layer "In4.Cu")
		(net "M_C_CPU0_SB_DQ<23>")
	)
	(segment
		(start 334.018636 -227.969318)
		(end 334.008222 -227.963222)
		(width 0.088646)
		(layer "In4.Cu")
		(net "M_C_CPU0_SB_DQ<23>")
	)
	(segment
		(start 340.041992 -227.963222)
		(end 340.031578 -227.969318)
		(width 0.088646)
		(layer "In4.Cu")
		(net "M_C_CPU0_SB_DQ<23>")
	)
	(segment
		(start 294.381682 -206.241904)
		(end 294.06088 -205.921102)
		(width 0.18288)
		(layer "In4.Cu")
		(net "M_C_CPU0_SB_DQ<23>")
	)
	(segment
		(start 335.898236 -227.969318)
		(end 335.887822 -227.963222)
		(width 0.088646)
		(layer "In4.Cu")
		(net "M_C_CPU0_SB_DQ<23>")
	)
	(segment
		(start 298.620688 -205.510892)
		(end 298.394374 -205.737206)
		(width 0.18288)
		(layer "In4.Cu")
		(net "M_C_CPU0_SB_DQ<23>")
	)
	(segment
		(start 297.603418 -206.241904)
		(end 294.381682 -206.241904)
		(width 0.18288)
		(layer "In4.Cu")
		(net "M_C_CPU0_SB_DQ<23>")
	)
	(segment
		(start 286.009842 -205.410816)
		(end 285.826962 -205.593696)
		(width 0.18288)
		(layer "In4.Cu")
		(net "M_C_CPU0_SB_DQ<23>")
	)
	(segment
		(start 284.096714 -204.786738)
		(end 283.916882 -204.96657)
		(width 0.18288)
		(layer "In4.Cu")
		(net "M_C_CPU0_SB_DQ<23>")
	)
	(segment
		(start 284.35554 -204.786738)
		(end 284.096714 -204.786738)
		(width 0.18288)
		(layer "In4.Cu")
		(net "M_C_CPU0_SB_DQ<23>")
	)
	(segment
		(start 299.71746 -205.706726)
		(end 299.401992 -205.391258)
		(width 0.18288)
		(layer "In4.Cu")
		(net "M_C_CPU0_SB_DQ<23>")
	)
	(segment
		(start 302.968152 -205.706726)
		(end 299.71746 -205.706726)
		(width 0.18288)
		(layer "In4.Cu")
		(net "M_C_CPU0_SB_DQ<23>")
	)
	(segment
		(start 332.523338 -227.975414)
		(end 332.259686 -227.975414)
		(width 0.088646)
		(layer "In4.Cu")
		(net "M_C_CPU0_SB_DQ<23>")
	)
	(segment
		(start 339.657182 -227.969318)
		(end 339.646768 -227.963222)
		(width 0.088646)
		(layer "In4.Cu")
		(net "M_C_CPU0_SB_DQ<23>")
	)
	(segment
		(start 340.941152 -228.45903)
		(end 340.876128 -228.394006)
		(width 0.088646)
		(layer "In4.Cu")
		(net "M_C_CPU0_SB_DQ<23>")
	)
	(segment
		(start 285.826962 -205.593696)
		(end 285.162498 -205.593696)
		(width 0.18288)
		(layer "In4.Cu")
		(net "M_C_CPU0_SB_DQ<23>")
	)
	(arc
		(start 340.876128 -228.394006)
		(mid 340.787059 -228.148577)
		(end 340.597236 -227.969318)
		(width 0.088646)
		(layer "In4.Cu")
		(net "M_C_CPU0_SB_DQ<23>")
	)
	(arc
		(start 340.597236 -227.969318)
		(mid 340.320423 -227.893482)
		(end 340.041992 -227.963222)
		(width 0.088646)
		(layer "In4.Cu")
		(net "M_C_CPU0_SB_DQ<23>")
	)
	(arc
		(start 338.152232 -227.969318)
		(mid 337.965034 -228.019461)
		(end 337.777836 -227.969318)
		(width 0.088646)
		(layer "In4.Cu")
		(net "M_C_CPU0_SB_DQ<23>")
	)
	(arc
		(start 336.272632 -227.969318)
		(mid 336.085434 -228.019461)
		(end 335.898236 -227.969318)
		(width 0.088646)
		(layer "In4.Cu")
		(net "M_C_CPU0_SB_DQ<23>")
	)
	(arc
		(start 335.887822 -227.963222)
		(mid 335.60939 -227.893408)
		(end 335.332578 -227.969318)
		(width 0.088646)
		(layer "In4.Cu")
		(net "M_C_CPU0_SB_DQ<23>")
	)
	(arc
		(start 333.452978 -227.969318)
		(mid 333.26578 -228.019461)
		(end 333.078582 -227.969318)
		(width 0.088646)
		(layer "In4.Cu")
		(net "M_C_CPU0_SB_DQ<23>")
	)
	(arc
		(start 337.777836 -227.969318)
		(mid 337.503607 -227.893393)
		(end 337.227164 -227.960682)
		(width 0.088646)
		(layer "In4.Cu")
		(net "M_C_CPU0_SB_DQ<23>")
	)
	(arc
		(start 340.031578 -227.969318)
		(mid 339.84438 -228.019461)
		(end 339.657182 -227.969318)
		(width 0.088646)
		(layer "In4.Cu")
		(net "M_C_CPU0_SB_DQ<23>")
	)
	(arc
		(start 339.646768 -227.963222)
		(mid 339.36859 -227.89353)
		(end 339.092032 -227.969318)
		(width 0.088646)
		(layer "In4.Cu")
		(net "M_C_CPU0_SB_DQ<23>")
	)
	(arc
		(start 336.838036 -227.969318)
		(mid 336.563807 -227.893393)
		(end 336.287364 -227.960682)
		(width 0.088646)
		(layer "In4.Cu")
		(net "M_C_CPU0_SB_DQ<23>")
	)
	(arc
		(start 337.212432 -227.969318)
		(mid 337.025234 -228.019461)
		(end 336.838036 -227.969318)
		(width 0.088646)
		(layer "In4.Cu")
		(net "M_C_CPU0_SB_DQ<23>")
	)
	(arc
		(start 333.078582 -227.969318)
		(mid 332.80015 -227.899504)
		(end 332.523338 -227.975414)
		(width 0.088646)
		(layer "In4.Cu")
		(net "M_C_CPU0_SB_DQ<23>")
	)
	(arc
		(start 339.092032 -227.969318)
		(mid 338.904834 -228.019461)
		(end 338.717636 -227.969318)
		(width 0.088646)
		(layer "In4.Cu")
		(net "M_C_CPU0_SB_DQ<23>")
	)
	(arc
		(start 338.717636 -227.969318)
		(mid 338.443407 -227.893393)
		(end 338.166964 -227.960682)
		(width 0.088646)
		(layer "In4.Cu")
		(net "M_C_CPU0_SB_DQ<23>")
	)
	(arc
		(start 334.947768 -227.963222)
		(mid 334.66959 -227.89353)
		(end 334.393032 -227.969318)
		(width 0.088646)
		(layer "In4.Cu")
		(net "M_C_CPU0_SB_DQ<23>")
	)
	(arc
		(start 334.008222 -227.963222)
		(mid 333.72979 -227.893408)
		(end 333.452978 -227.969318)
		(width 0.088646)
		(layer "In4.Cu")
		(net "M_C_CPU0_SB_DQ<23>")
	)
	(arc
		(start 335.332578 -227.969318)
		(mid 335.14538 -228.019461)
		(end 334.958182 -227.969318)
		(width 0.088646)
		(layer "In4.Cu")
		(net "M_C_CPU0_SB_DQ<23>")
	)
	(arc
		(start 334.393032 -227.969318)
		(mid 334.205834 -228.019461)
		(end 334.018636 -227.969318)
		(width 0.088646)
		(layer "In4.Cu")
		(net "M_C_CPU0_SB_DQ<23>")
	)
	(segment
		(start 277.59787 -206.24165)
		(end 277.58771 -206.23149)
		(width 0.101854)
		(layer "F.Cu")
		(net "M_C_CPU0_SB_DQ<22>")
	)
	(segment
		(start 341.724234 -229.808532)
		(end 341.724234 -229.272846)
		(width 0.20066)
		(layer "F.Cu")
		(net "M_C_CPU0_SB_DQ<22>")
	)
	(segment
		(start 280.545794 -206.24165)
		(end 279.912826 -206.24165)
		(width 0.20066)
		(layer "F.Cu")
		(net "M_C_CPU0_SB_DQ<22>")
	)
	(segment
		(start 276.415246 -206.666592)
		(end 275.268182 -206.666592)
		(width 0.20066)
		(layer "F.Cu")
		(net "M_C_CPU0_SB_DQ<22>")
	)
	(segment
		(start 281.285442 -206.878428)
		(end 280.856944 -206.878428)
		(width 0.20066)
		(layer "F.Cu")
		(net "M_C_CPU0_SB_DQ<22>")
	)
	(segment
		(start 341.72398 -229.808786)
		(end 341.724234 -229.808532)
		(width 0.20066)
		(layer "F.Cu")
		(net "M_C_CPU0_SB_DQ<22>")
	)
	(segment
		(start 280.689558 -206.385414)
		(end 280.545794 -206.24165)
		(width 0.20066)
		(layer "F.Cu")
		(net "M_C_CPU0_SB_DQ<22>")
	)
	(segment
		(start 282.811982 -206.666592)
		(end 281.497278 -206.666592)
		(width 0.20066)
		(layer "F.Cu")
		(net "M_C_CPU0_SB_DQ<22>")
	)
	(segment
		(start 276.850348 -206.23149)
		(end 276.415246 -206.666592)
		(width 0.20066)
		(layer "F.Cu")
		(net "M_C_CPU0_SB_DQ<22>")
	)
	(segment
		(start 277.58771 -206.23149)
		(end 276.850348 -206.23149)
		(width 0.20066)
		(layer "F.Cu")
		(net "M_C_CPU0_SB_DQ<22>")
	)
	(segment
		(start 279.912826 -206.24165)
		(end 277.852886 -206.24165)
		(width 0.1016)
		(layer "F.Cu")
		(net "M_C_CPU0_SB_DQ<22>")
	)
	(segment
		(start 283.916882 -206.666592)
		(end 282.811982 -206.666592)
		(width 0.20066)
		(layer "F.Cu")
		(net "M_C_CPU0_SB_DQ<22>")
	)
	(segment
		(start 277.852886 -206.24165)
		(end 277.59787 -206.24165)
		(width 0.101854)
		(layer "F.Cu")
		(net "M_C_CPU0_SB_DQ<22>")
	)
	(segment
		(start 280.856944 -206.878428)
		(end 280.689558 -206.711042)
		(width 0.20066)
		(layer "F.Cu")
		(net "M_C_CPU0_SB_DQ<22>")
	)
	(segment
		(start 280.689558 -206.711042)
		(end 280.689558 -206.385414)
		(width 0.20066)
		(layer "F.Cu")
		(net "M_C_CPU0_SB_DQ<22>")
	)
	(segment
		(start 281.497278 -206.666592)
		(end 281.285442 -206.878428)
		(width 0.20066)
		(layer "F.Cu")
		(net "M_C_CPU0_SB_DQ<22>")
	)
	(segment
		(start 291.096954 -208.046066)
		(end 290.030662 -206.979774)
		(width 0.18288)
		(layer "In4.Cu")
		(net "M_C_CPU0_SB_DQ<22>")
	)
	(segment
		(start 337.682332 -228.783388)
		(end 337.67776 -228.785928)
		(width 0.088646)
		(layer "In4.Cu")
		(net "M_C_CPU0_SB_DQ<22>")
	)
	(segment
		(start 293.05631 -207.679036)
		(end 292.442392 -207.679036)
		(width 0.18288)
		(layer "In4.Cu")
		(net "M_C_CPU0_SB_DQ<22>")
	)
	(segment
		(start 307.349906 -207.89773)
		(end 307.131466 -208.11617)
		(width 0.18288)
		(layer "In4.Cu")
		(net "M_C_CPU0_SB_DQ<22>")
	)
	(segment
		(start 301.064168 -207.274922)
		(end 300.881288 -207.092042)
		(width 0.18288)
		(layer "In4.Cu")
		(net "M_C_CPU0_SB_DQ<22>")
	)
	(segment
		(start 338.629498 -228.77907)
		(end 338.622132 -228.783388)
		(width 0.088646)
		(layer "In4.Cu")
		(net "M_C_CPU0_SB_DQ<22>")
	)
	(segment
		(start 310.636666 -207.89773)
		(end 307.349906 -207.89773)
		(width 0.18288)
		(layer "In4.Cu")
		(net "M_C_CPU0_SB_DQ<22>")
	)
	(segment
		(start 292.075362 -208.046066)
		(end 291.096954 -208.046066)
		(width 0.18288)
		(layer "In4.Cu")
		(net "M_C_CPU0_SB_DQ<22>")
	)
	(segment
		(start 305.539394 -207.93329)
		(end 305.539394 -207.606646)
		(width 0.18288)
		(layer "In4.Cu")
		(net "M_C_CPU0_SB_DQ<22>")
	)
	(segment
		(start 311.65038 -208.911444)
		(end 310.636666 -207.89773)
		(width 0.18288)
		(layer "In4.Cu")
		(net "M_C_CPU0_SB_DQ<22>")
	)
	(segment
		(start 301.26432 -208.193386)
		(end 301.064168 -207.993234)
		(width 0.18288)
		(layer "In4.Cu")
		(net "M_C_CPU0_SB_DQ<22>")
	)
	(segment
		(start 301.937928 -207.092042)
		(end 301.755048 -207.274922)
		(width 0.18288)
		(layer "In4.Cu")
		(net "M_C_CPU0_SB_DQ<22>")
	)
	(segment
		(start 320.504058 -221.418404)
		(end 315.881004 -210.257898)
		(width 0.18288)
		(layer "In4.Cu")
		(net "M_C_CPU0_SB_DQ<22>")
	)
	(segment
		(start 302.760126 -207.092042)
		(end 301.937928 -207.092042)
		(width 0.18288)
		(layer "In4.Cu")
		(net "M_C_CPU0_SB_DQ<22>")
	)
	(segment
		(start 336.749898 -228.77907)
		(end 336.742532 -228.783388)
		(width 0.088646)
		(layer "In4.Cu")
		(net "M_C_CPU0_SB_DQ<22>")
	)
	(segment
		(start 301.755048 -207.274922)
		(end 301.755048 -208.010506)
		(width 0.18288)
		(layer "In4.Cu")
		(net "M_C_CPU0_SB_DQ<22>")
	)
	(segment
		(start 305.031394 -207.423766)
		(end 304.848514 -207.606646)
		(width 0.18288)
		(layer "In4.Cu")
		(net "M_C_CPU0_SB_DQ<22>")
	)
	(segment
		(start 301.064168 -207.993234)
		(end 301.064168 -207.274922)
		(width 0.18288)
		(layer "In4.Cu")
		(net "M_C_CPU0_SB_DQ<22>")
	)
	(segment
		(start 339.561932 -228.783388)
		(end 339.55736 -228.785928)
		(width 0.088646)
		(layer "In4.Cu")
		(net "M_C_CPU0_SB_DQ<22>")
	)
	(segment
		(start 340.509098 -228.77907)
		(end 340.501732 -228.783388)
		(width 0.088646)
		(layer "In4.Cu")
		(net "M_C_CPU0_SB_DQ<22>")
	)
	(segment
		(start 284.614874 -207.364584)
		(end 283.916882 -206.666592)
		(width 0.18288)
		(layer "In4.Cu")
		(net "M_C_CPU0_SB_DQ<22>")
	)
	(segment
		(start 290.030662 -206.979774)
		(end 288.438082 -206.979774)
		(width 0.18288)
		(layer "In4.Cu")
		(net "M_C_CPU0_SB_DQ<22>")
	)
	(segment
		(start 293.318946 -207.941672)
		(end 293.05631 -207.679036)
		(width 0.18288)
		(layer "In4.Cu")
		(net "M_C_CPU0_SB_DQ<22>")
	)
	(segment
		(start 335.428082 -228.783388)
		(end 335.428336 -228.783388)
		(width 0.088646)
		(layer "In4.Cu")
		(net "M_C_CPU0_SB_DQ<22>")
	)
	(segment
		(start 288.438082 -206.979774)
		(end 288.053272 -207.364584)
		(width 0.18288)
		(layer "In4.Cu")
		(net "M_C_CPU0_SB_DQ<22>")
	)
	(segment
		(start 331.86116 -228.783388)
		(end 331.808074 -228.730302)
		(width 0.088646)
		(layer "In4.Cu")
		(net "M_C_CPU0_SB_DQ<22>")
	)
	(segment
		(start 341.143336 -228.82733)
		(end 341.066882 -228.783388)
		(width 0.088646)
		(layer "In4.Cu")
		(net "M_C_CPU0_SB_DQ<22>")
	)
	(segment
		(start 335.802732 -228.783388)
		(end 335.798414 -228.785928)
		(width 0.088646)
		(layer "In4.Cu")
		(net "M_C_CPU0_SB_DQ<22>")
	)
	(segment
		(start 297.63212 -207.941672)
		(end 293.318946 -207.941672)
		(width 0.18288)
		(layer "In4.Cu")
		(net "M_C_CPU0_SB_DQ<22>")
	)
	(segment
		(start 301.572168 -208.193386)
		(end 301.26432 -208.193386)
		(width 0.18288)
		(layer "In4.Cu")
		(net "M_C_CPU0_SB_DQ<22>")
	)
	(segment
		(start 304.665634 -208.11617)
		(end 303.784254 -208.11617)
		(width 0.18288)
		(layer "In4.Cu")
		(net "M_C_CPU0_SB_DQ<22>")
	)
	(segment
		(start 331.808074 -228.730302)
		(end 331.808074 -228.185726)
		(width 0.088646)
		(layer "In4.Cu")
		(net "M_C_CPU0_SB_DQ<22>")
	)
	(segment
		(start 331.808074 -228.185726)
		(end 330.97978 -227.357432)
		(width 0.088646)
		(layer "In4.Cu")
		(net "M_C_CPU0_SB_DQ<22>")
	)
	(segment
		(start 301.755048 -208.010506)
		(end 301.572168 -208.193386)
		(width 0.18288)
		(layer "In4.Cu")
		(net "M_C_CPU0_SB_DQ<22>")
	)
	(segment
		(start 332.043532 -228.783388)
		(end 331.86116 -228.783388)
		(width 0.088646)
		(layer "In4.Cu")
		(net "M_C_CPU0_SB_DQ<22>")
	)
	(segment
		(start 314.53455 -208.911444)
		(end 311.65038 -208.911444)
		(width 0.18288)
		(layer "In4.Cu")
		(net "M_C_CPU0_SB_DQ<22>")
	)
	(segment
		(start 300.881288 -207.092042)
		(end 298.48175 -207.092042)
		(width 0.18288)
		(layer "In4.Cu")
		(net "M_C_CPU0_SB_DQ<22>")
	)
	(segment
		(start 288.053272 -207.364584)
		(end 284.614874 -207.364584)
		(width 0.18288)
		(layer "In4.Cu")
		(net "M_C_CPU0_SB_DQ<22>")
	)
	(segment
		(start 298.48175 -207.092042)
		(end 297.63212 -207.941672)
		(width 0.18288)
		(layer "In4.Cu")
		(net "M_C_CPU0_SB_DQ<22>")
	)
	(segment
		(start 305.722274 -208.11617)
		(end 305.539394 -207.93329)
		(width 0.18288)
		(layer "In4.Cu")
		(net "M_C_CPU0_SB_DQ<22>")
	)
	(segment
		(start 292.442392 -207.679036)
		(end 292.075362 -208.046066)
		(width 0.18288)
		(layer "In4.Cu")
		(net "M_C_CPU0_SB_DQ<22>")
	)
	(segment
		(start 336.742532 -228.783388)
		(end 336.739738 -228.784912)
		(width 0.088646)
		(layer "In4.Cu")
		(net "M_C_CPU0_SB_DQ<22>")
	)
	(segment
		(start 330.97978 -227.357432)
		(end 330.648564 -227.357432)
		(width 0.088646)
		(layer "In4.Cu")
		(net "M_C_CPU0_SB_DQ<22>")
	)
	(segment
		(start 305.356514 -207.423766)
		(end 305.031394 -207.423766)
		(width 0.18288)
		(layer "In4.Cu")
		(net "M_C_CPU0_SB_DQ<22>")
	)
	(segment
		(start 305.539394 -207.606646)
		(end 305.356514 -207.423766)
		(width 0.18288)
		(layer "In4.Cu")
		(net "M_C_CPU0_SB_DQ<22>")
	)
	(segment
		(start 307.131466 -208.11617)
		(end 305.722274 -208.11617)
		(width 0.18288)
		(layer "In4.Cu")
		(net "M_C_CPU0_SB_DQ<22>")
	)
	(segment
		(start 338.622132 -228.783388)
		(end 338.61756 -228.785928)
		(width 0.088646)
		(layer "In4.Cu")
		(net "M_C_CPU0_SB_DQ<22>")
	)
	(segment
		(start 304.848514 -207.606646)
		(end 304.848514 -207.93329)
		(width 0.18288)
		(layer "In4.Cu")
		(net "M_C_CPU0_SB_DQ<22>")
	)
	(segment
		(start 337.689698 -228.77907)
		(end 337.682332 -228.783388)
		(width 0.088646)
		(layer "In4.Cu")
		(net "M_C_CPU0_SB_DQ<22>")
	)
	(segment
		(start 330.648564 -227.357432)
		(end 326.443086 -227.357432)
		(width 0.18288)
		(layer "In4.Cu")
		(net "M_C_CPU0_SB_DQ<22>")
	)
	(segment
		(start 303.784254 -208.11617)
		(end 302.760126 -207.092042)
		(width 0.18288)
		(layer "In4.Cu")
		(net "M_C_CPU0_SB_DQ<22>")
	)
	(segment
		(start 339.569298 -228.77907)
		(end 339.561932 -228.783388)
		(width 0.088646)
		(layer "In4.Cu")
		(net "M_C_CPU0_SB_DQ<22>")
	)
	(segment
		(start 304.848514 -207.93329)
		(end 304.665634 -208.11617)
		(width 0.18288)
		(layer "In4.Cu")
		(net "M_C_CPU0_SB_DQ<22>")
	)
	(segment
		(start 326.443086 -227.357432)
		(end 320.504058 -221.418404)
		(width 0.18288)
		(layer "In4.Cu")
		(net "M_C_CPU0_SB_DQ<22>")
	)
	(segment
		(start 340.501732 -228.783388)
		(end 340.49716 -228.785928)
		(width 0.088646)
		(layer "In4.Cu")
		(net "M_C_CPU0_SB_DQ<22>")
	)
	(segment
		(start 315.881004 -210.257898)
		(end 314.53455 -208.911444)
		(width 0.18288)
		(layer "In4.Cu")
		(net "M_C_CPU0_SB_DQ<22>")
	)
	(arc
		(start 340.127082 -228.783388)
		(mid 339.848759 -228.707629)
		(end 339.569298 -228.77907)
		(width 0.088646)
		(layer "In4.Cu")
		(net "M_C_CPU0_SB_DQ<22>")
	)
	(arc
		(start 341.724234 -229.272846)
		(mid 341.448442 -229.030977)
		(end 341.143336 -228.82733)
		(width 0.088646)
		(layer "In4.Cu")
		(net "M_C_CPU0_SB_DQ<22>")
	)
	(arc
		(start 335.428336 -228.783388)
		(mid 335.145634 -228.707612)
		(end 334.862932 -228.783388)
		(width 0.088646)
		(layer "In4.Cu")
		(net "M_C_CPU0_SB_DQ<22>")
	)
	(arc
		(start 336.739738 -228.784912)
		(mid 336.553599 -228.83359)
		(end 336.367882 -228.783388)
		(width 0.088646)
		(layer "In4.Cu")
		(net "M_C_CPU0_SB_DQ<22>")
	)
	(arc
		(start 340.49716 -228.785928)
		(mid 340.311775 -228.833598)
		(end 340.127082 -228.783388)
		(width 0.088646)
		(layer "In4.Cu")
		(net "M_C_CPU0_SB_DQ<22>")
	)
	(arc
		(start 334.862932 -228.783388)
		(mid 334.675734 -228.833531)
		(end 334.488536 -228.783388)
		(width 0.088646)
		(layer "In4.Cu")
		(net "M_C_CPU0_SB_DQ<22>")
	)
	(arc
		(start 339.187282 -228.783388)
		(mid 338.908959 -228.707629)
		(end 338.629498 -228.77907)
		(width 0.088646)
		(layer "In4.Cu")
		(net "M_C_CPU0_SB_DQ<22>")
	)
	(arc
		(start 338.247482 -228.783388)
		(mid 337.969159 -228.707629)
		(end 337.689698 -228.77907)
		(width 0.088646)
		(layer "In4.Cu")
		(net "M_C_CPU0_SB_DQ<22>")
	)
	(arc
		(start 337.67776 -228.785928)
		(mid 337.492375 -228.833598)
		(end 337.307682 -228.783388)
		(width 0.088646)
		(layer "In4.Cu")
		(net "M_C_CPU0_SB_DQ<22>")
	)
	(arc
		(start 341.066882 -228.783388)
		(mid 340.788559 -228.707629)
		(end 340.509098 -228.77907)
		(width 0.088646)
		(layer "In4.Cu")
		(net "M_C_CPU0_SB_DQ<22>")
	)
	(arc
		(start 338.61756 -228.785928)
		(mid 338.432175 -228.833598)
		(end 338.247482 -228.783388)
		(width 0.088646)
		(layer "In4.Cu")
		(net "M_C_CPU0_SB_DQ<22>")
	)
	(arc
		(start 336.367882 -228.783388)
		(mid 336.085324 -228.707739)
		(end 335.802732 -228.783388)
		(width 0.088646)
		(layer "In4.Cu")
		(net "M_C_CPU0_SB_DQ<22>")
	)
	(arc
		(start 333.548736 -228.783388)
		(mid 333.266034 -228.707612)
		(end 332.983332 -228.783388)
		(width 0.088646)
		(layer "In4.Cu")
		(net "M_C_CPU0_SB_DQ<22>")
	)
	(arc
		(start 334.488536 -228.783388)
		(mid 334.205834 -228.707612)
		(end 333.923132 -228.783388)
		(width 0.088646)
		(layer "In4.Cu")
		(net "M_C_CPU0_SB_DQ<22>")
	)
	(arc
		(start 335.798414 -228.785928)
		(mid 335.612919 -228.833597)
		(end 335.428082 -228.783388)
		(width 0.088646)
		(layer "In4.Cu")
		(net "M_C_CPU0_SB_DQ<22>")
	)
	(arc
		(start 339.55736 -228.785928)
		(mid 339.371975 -228.833598)
		(end 339.187282 -228.783388)
		(width 0.088646)
		(layer "In4.Cu")
		(net "M_C_CPU0_SB_DQ<22>")
	)
	(arc
		(start 332.983332 -228.783388)
		(mid 332.796134 -228.833531)
		(end 332.608936 -228.783388)
		(width 0.088646)
		(layer "In4.Cu")
		(net "M_C_CPU0_SB_DQ<22>")
	)
	(arc
		(start 337.307682 -228.783388)
		(mid 337.029359 -228.707629)
		(end 336.749898 -228.77907)
		(width 0.088646)
		(layer "In4.Cu")
		(net "M_C_CPU0_SB_DQ<22>")
	)
	(arc
		(start 332.608936 -228.783388)
		(mid 332.326234 -228.707612)
		(end 332.043532 -228.783388)
		(width 0.088646)
		(layer "In4.Cu")
		(net "M_C_CPU0_SB_DQ<22>")
	)
	(arc
		(start 333.923132 -228.783388)
		(mid 333.735934 -228.833531)
		(end 333.548736 -228.783388)
		(width 0.088646)
		(layer "In4.Cu")
		(net "M_C_CPU0_SB_DQ<22>")
	)
	(segment
		(start 274.152868 -205.391766)
		(end 274.143978 -205.382876)
		(width 0.1016)
		(layer "F.Cu")
		(net "M_C_CPU0_SB_DQ<21>")
	)
	(segment
		(start 276.469094 -205.391766)
		(end 276.138386 -205.391766)
		(width 0.101854)
		(layer "F.Cu")
		(net "M_C_CPU0_SB_DQ<21>")
	)
	(segment
		(start 272.502376 -205.816708)
		(end 271.168114 -205.816708)
		(width 0.20066)
		(layer "F.Cu")
		(net "M_C_CPU0_SB_DQ<21>")
	)
	(segment
		(start 276.647656 -205.391766)
		(end 276.469094 -205.391766)
		(width 0.20066)
		(layer "F.Cu")
		(net "M_C_CPU0_SB_DQ<21>")
	)
	(segment
		(start 273.53514 -205.382876)
		(end 273.37258 -205.545436)
		(width 0.20066)
		(layer "F.Cu")
		(net "M_C_CPU0_SB_DQ<21>")
	)
	(segment
		(start 340.31428 -228.994716)
		(end 340.31428 -228.45903)
		(width 0.20066)
		(layer "F.Cu")
		(net "M_C_CPU0_SB_DQ<21>")
	)
	(segment
		(start 272.713704 -206.028036)
		(end 272.502376 -205.816708)
		(width 0.20066)
		(layer "F.Cu")
		(net "M_C_CPU0_SB_DQ<21>")
	)
	(segment
		(start 277.072598 -205.816708)
		(end 276.647656 -205.391766)
		(width 0.20066)
		(layer "F.Cu")
		(net "M_C_CPU0_SB_DQ<21>")
	)
	(segment
		(start 340.314534 -228.99497)
		(end 340.31428 -228.994716)
		(width 0.20066)
		(layer "F.Cu")
		(net "M_C_CPU0_SB_DQ<21>")
	)
	(segment
		(start 278.711914 -205.816708)
		(end 277.072598 -205.816708)
		(width 0.20066)
		(layer "F.Cu")
		(net "M_C_CPU0_SB_DQ<21>")
	)
	(segment
		(start 276.138386 -205.391766)
		(end 274.152868 -205.391766)
		(width 0.1016)
		(layer "F.Cu")
		(net "M_C_CPU0_SB_DQ<21>")
	)
	(segment
		(start 273.218148 -206.028036)
		(end 272.713704 -206.028036)
		(width 0.20066)
		(layer "F.Cu")
		(net "M_C_CPU0_SB_DQ<21>")
	)
	(segment
		(start 279.816814 -205.816708)
		(end 278.711914 -205.816708)
		(width 0.20066)
		(layer "F.Cu")
		(net "M_C_CPU0_SB_DQ<21>")
	)
	(segment
		(start 273.37258 -205.545436)
		(end 273.37258 -205.873604)
		(width 0.20066)
		(layer "F.Cu")
		(net "M_C_CPU0_SB_DQ<21>")
	)
	(segment
		(start 273.37258 -205.873604)
		(end 273.218148 -206.028036)
		(width 0.20066)
		(layer "F.Cu")
		(net "M_C_CPU0_SB_DQ<21>")
	)
	(segment
		(start 274.143978 -205.382876)
		(end 273.53514 -205.382876)
		(width 0.20066)
		(layer "F.Cu")
		(net "M_C_CPU0_SB_DQ<21>")
	)
	(segment
		(start 339.187536 -228.134672)
		(end 339.177122 -228.140768)
		(width 0.088646)
		(layer "In4.Cu")
		(net "M_C_CPU0_SB_DQ<21>")
	)
	(segment
		(start 284.195266 -205.39202)
		(end 280.241502 -205.39202)
		(width 0.18288)
		(layer "In4.Cu")
		(net "M_C_CPU0_SB_DQ<21>")
	)
	(segment
		(start 340.510368 -228.139752)
		(end 340.501478 -228.134672)
		(width 0.088646)
		(layer "In4.Cu")
		(net "M_C_CPU0_SB_DQ<21>")
	)
	(segment
		(start 291.912802 -207.092042)
		(end 291.149278 -206.328518)
		(width 0.18288)
		(layer "In4.Cu")
		(net "M_C_CPU0_SB_DQ<21>")
	)
	(segment
		(start 310.80075 -207.320388)
		(end 307.19141 -207.320388)
		(width 0.18288)
		(layer "In4.Cu")
		(net "M_C_CPU0_SB_DQ<21>")
	)
	(segment
		(start 331.439774 -227.390452)
		(end 330.908914 -226.859592)
		(width 0.088646)
		(layer "In4.Cu")
		(net "M_C_CPU0_SB_DQ<21>")
	)
	(segment
		(start 326.680068 -226.859592)
		(end 320.904362 -221.083886)
		(width 0.18288)
		(layer "In4.Cu")
		(net "M_C_CPU0_SB_DQ<21>")
	)
	(segment
		(start 291.149278 -206.328518)
		(end 288.801048 -206.328518)
		(width 0.18288)
		(layer "In4.Cu")
		(net "M_C_CPU0_SB_DQ<21>")
	)
	(segment
		(start 337.307682 -228.134672)
		(end 337.29295 -228.143308)
		(width 0.088646)
		(layer "In4.Cu")
		(net "M_C_CPU0_SB_DQ<21>")
	)
	(segment
		(start 340.31428 -228.45903)
		(end 340.627208 -228.45903)
		(width 0.088646)
		(layer "In4.Cu")
		(net "M_C_CPU0_SB_DQ<21>")
	)
	(segment
		(start 316.183264 -209.686144)
		(end 314.81776 -208.32064)
		(width 0.18288)
		(layer "In4.Cu")
		(net "M_C_CPU0_SB_DQ<21>")
	)
	(segment
		(start 297.631612 -207.092042)
		(end 291.912802 -207.092042)
		(width 0.18288)
		(layer "In4.Cu")
		(net "M_C_CPU0_SB_DQ<21>")
	)
	(segment
		(start 302.759872 -206.241904)
		(end 298.48175 -206.241904)
		(width 0.18288)
		(layer "In4.Cu")
		(net "M_C_CPU0_SB_DQ<21>")
	)
	(segment
		(start 280.241502 -205.39202)
		(end 279.816814 -205.816708)
		(width 0.18288)
		(layer "In4.Cu")
		(net "M_C_CPU0_SB_DQ<21>")
	)
	(segment
		(start 340.627208 -228.45903)
		(end 340.684358 -228.40188)
		(width 0.088646)
		(layer "In4.Cu")
		(net "M_C_CPU0_SB_DQ<21>")
	)
	(segment
		(start 311.801002 -208.32064)
		(end 310.80075 -207.320388)
		(width 0.18288)
		(layer "In4.Cu")
		(net "M_C_CPU0_SB_DQ<21>")
	)
	(segment
		(start 334.877664 -228.143308)
		(end 334.862932 -228.134672)
		(width 0.088646)
		(layer "In4.Cu")
		(net "M_C_CPU0_SB_DQ<21>")
	)
	(segment
		(start 288.801048 -206.328518)
		(end 288.585402 -206.112872)
		(width 0.18288)
		(layer "In4.Cu")
		(net "M_C_CPU0_SB_DQ<21>")
	)
	(segment
		(start 314.81776 -208.32064)
		(end 311.801002 -208.32064)
		(width 0.18288)
		(layer "In4.Cu")
		(net "M_C_CPU0_SB_DQ<21>")
	)
	(segment
		(start 284.916118 -206.112872)
		(end 284.195266 -205.39202)
		(width 0.18288)
		(layer "In4.Cu")
		(net "M_C_CPU0_SB_DQ<21>")
	)
	(segment
		(start 307.19141 -207.320388)
		(end 306.796948 -206.925926)
		(width 0.18288)
		(layer "In4.Cu")
		(net "M_C_CPU0_SB_DQ<21>")
	)
	(segment
		(start 330.648564 -226.859592)
		(end 326.680068 -226.859592)
		(width 0.18288)
		(layer "In4.Cu")
		(net "M_C_CPU0_SB_DQ<21>")
	)
	(segment
		(start 331.439774 -227.53447)
		(end 331.439774 -227.390452)
		(width 0.088646)
		(layer "In4.Cu")
		(net "M_C_CPU0_SB_DQ<21>")
	)
	(segment
		(start 298.48175 -206.241904)
		(end 297.631612 -207.092042)
		(width 0.18288)
		(layer "In4.Cu")
		(net "M_C_CPU0_SB_DQ<21>")
	)
	(segment
		(start 320.904362 -221.083886)
		(end 316.183264 -209.686144)
		(width 0.18288)
		(layer "In4.Cu")
		(net "M_C_CPU0_SB_DQ<21>")
	)
	(segment
		(start 288.585402 -206.112872)
		(end 284.916118 -206.112872)
		(width 0.18288)
		(layer "In4.Cu")
		(net "M_C_CPU0_SB_DQ<21>")
	)
	(segment
		(start 330.908914 -226.859592)
		(end 330.648564 -226.859592)
		(width 0.088646)
		(layer "In4.Cu")
		(net "M_C_CPU0_SB_DQ<21>")
	)
	(segment
		(start 306.796948 -206.925926)
		(end 303.443894 -206.925926)
		(width 0.18288)
		(layer "In4.Cu")
		(net "M_C_CPU0_SB_DQ<21>")
	)
	(segment
		(start 336.367882 -228.134672)
		(end 336.357468 -228.140768)
		(width 0.088646)
		(layer "In4.Cu")
		(net "M_C_CPU0_SB_DQ<21>")
	)
	(segment
		(start 338.247482 -228.134672)
		(end 338.23275 -228.143308)
		(width 0.088646)
		(layer "In4.Cu")
		(net "M_C_CPU0_SB_DQ<21>")
	)
	(segment
		(start 339.572346 -228.140768)
		(end 339.561932 -228.134672)
		(width 0.088646)
		(layer "In4.Cu")
		(net "M_C_CPU0_SB_DQ<21>")
	)
	(segment
		(start 303.443894 -206.925926)
		(end 302.759872 -206.241904)
		(width 0.18288)
		(layer "In4.Cu")
		(net "M_C_CPU0_SB_DQ<21>")
	)
	(segment
		(start 332.058264 -228.143308)
		(end 332.048612 -228.143308)
		(width 0.088646)
		(layer "In4.Cu")
		(net "M_C_CPU0_SB_DQ<21>")
	)
	(segment
		(start 332.048612 -228.143308)
		(end 331.439774 -227.53447)
		(width 0.088646)
		(layer "In4.Cu")
		(net "M_C_CPU0_SB_DQ<21>")
	)
	(arc
		(start 336.357468 -228.140768)
		(mid 336.07929 -228.21046)
		(end 335.802732 -228.134672)
		(width 0.088646)
		(layer "In4.Cu")
		(net "M_C_CPU0_SB_DQ<21>")
	)
	(arc
		(start 339.177122 -228.140768)
		(mid 338.89869 -228.210582)
		(end 338.621878 -228.134672)
		(width 0.088646)
		(layer "In4.Cu")
		(net "M_C_CPU0_SB_DQ<21>")
	)
	(arc
		(start 335.428336 -228.134672)
		(mid 335.154107 -228.210597)
		(end 334.877664 -228.143308)
		(width 0.088646)
		(layer "In4.Cu")
		(net "M_C_CPU0_SB_DQ<21>")
	)
	(arc
		(start 332.998064 -228.143308)
		(mid 332.810866 -228.093165)
		(end 332.623668 -228.143308)
		(width 0.088646)
		(layer "In4.Cu")
		(net "M_C_CPU0_SB_DQ<21>")
	)
	(arc
		(start 338.621878 -228.134672)
		(mid 338.43468 -228.084529)
		(end 338.247482 -228.134672)
		(width 0.088646)
		(layer "In4.Cu")
		(net "M_C_CPU0_SB_DQ<21>")
	)
	(arc
		(start 333.548736 -228.134672)
		(mid 333.274507 -228.210597)
		(end 332.998064 -228.143308)
		(width 0.088646)
		(layer "In4.Cu")
		(net "M_C_CPU0_SB_DQ<21>")
	)
	(arc
		(start 339.561932 -228.134672)
		(mid 339.374734 -228.084529)
		(end 339.187536 -228.134672)
		(width 0.088646)
		(layer "In4.Cu")
		(net "M_C_CPU0_SB_DQ<21>")
	)
	(arc
		(start 334.862932 -228.134672)
		(mid 334.675734 -228.084529)
		(end 334.488536 -228.134672)
		(width 0.088646)
		(layer "In4.Cu")
		(net "M_C_CPU0_SB_DQ<21>")
	)
	(arc
		(start 332.623668 -228.143308)
		(mid 332.340966 -228.210613)
		(end 332.058264 -228.143308)
		(width 0.088646)
		(layer "In4.Cu")
		(net "M_C_CPU0_SB_DQ<21>")
	)
	(arc
		(start 334.488536 -228.134672)
		(mid 334.205834 -228.210414)
		(end 333.923132 -228.134672)
		(width 0.088646)
		(layer "In4.Cu")
		(net "M_C_CPU0_SB_DQ<21>")
	)
	(arc
		(start 336.742278 -228.134672)
		(mid 336.55508 -228.084529)
		(end 336.367882 -228.134672)
		(width 0.088646)
		(layer "In4.Cu")
		(net "M_C_CPU0_SB_DQ<21>")
	)
	(arc
		(start 335.802732 -228.134672)
		(mid 335.615534 -228.084529)
		(end 335.428336 -228.134672)
		(width 0.088646)
		(layer "In4.Cu")
		(net "M_C_CPU0_SB_DQ<21>")
	)
	(arc
		(start 340.501478 -228.134672)
		(mid 340.31428 -228.084529)
		(end 340.127082 -228.134672)
		(width 0.088646)
		(layer "In4.Cu")
		(net "M_C_CPU0_SB_DQ<21>")
	)
	(arc
		(start 337.682078 -228.134672)
		(mid 337.49488 -228.084529)
		(end 337.307682 -228.134672)
		(width 0.088646)
		(layer "In4.Cu")
		(net "M_C_CPU0_SB_DQ<21>")
	)
	(arc
		(start 340.684358 -228.40188)
		(mid 340.626239 -228.251639)
		(end 340.510368 -228.139752)
		(width 0.088646)
		(layer "In4.Cu")
		(net "M_C_CPU0_SB_DQ<21>")
	)
	(arc
		(start 338.23275 -228.143308)
		(mid 337.956309 -228.210474)
		(end 337.682078 -228.134672)
		(width 0.088646)
		(layer "In4.Cu")
		(net "M_C_CPU0_SB_DQ<21>")
	)
	(arc
		(start 333.923132 -228.134672)
		(mid 333.735934 -228.084529)
		(end 333.548736 -228.134672)
		(width 0.088646)
		(layer "In4.Cu")
		(net "M_C_CPU0_SB_DQ<21>")
	)
	(arc
		(start 337.29295 -228.143308)
		(mid 337.016509 -228.210474)
		(end 336.742278 -228.134672)
		(width 0.088646)
		(layer "In4.Cu")
		(net "M_C_CPU0_SB_DQ<21>")
	)
	(arc
		(start 340.127082 -228.134672)
		(mid 339.850523 -228.210381)
		(end 339.572346 -228.140768)
		(width 0.088646)
		(layer "In4.Cu")
		(net "M_C_CPU0_SB_DQ<21>")
	)
	(segment
		(start 272.502376 -207.51673)
		(end 271.168114 -207.51673)
		(width 0.20066)
		(layer "F.Cu")
		(net "M_C_CPU0_SB_DQ<20>")
	)
	(segment
		(start 339.84438 -229.808786)
		(end 339.844634 -229.808532)
		(width 0.20066)
		(layer "F.Cu")
		(net "M_C_CPU0_SB_DQ<20>")
	)
	(segment
		(start 339.844634 -229.808532)
		(end 339.844634 -229.272846)
		(width 0.20066)
		(layer "F.Cu")
		(net "M_C_CPU0_SB_DQ<20>")
	)
	(segment
		(start 274.152106 -207.091788)
		(end 274.143978 -207.08366)
		(width 0.101854)
		(layer "F.Cu")
		(net "M_C_CPU0_SB_DQ<20>")
	)
	(segment
		(start 277.342854 -207.51673)
		(end 276.917912 -207.091788)
		(width 0.20066)
		(layer "F.Cu")
		(net "M_C_CPU0_SB_DQ<20>")
	)
	(segment
		(start 276.917912 -207.091788)
		(end 276.469094 -207.091788)
		(width 0.20066)
		(layer "F.Cu")
		(net "M_C_CPU0_SB_DQ<20>")
	)
	(segment
		(start 273.37258 -207.58277)
		(end 273.19986 -207.75549)
		(width 0.20066)
		(layer "F.Cu")
		(net "M_C_CPU0_SB_DQ<20>")
	)
	(segment
		(start 274.143978 -207.08366)
		(end 273.58213 -207.08366)
		(width 0.20066)
		(layer "F.Cu")
		(net "M_C_CPU0_SB_DQ<20>")
	)
	(segment
		(start 273.58213 -207.08366)
		(end 273.37258 -207.29321)
		(width 0.20066)
		(layer "F.Cu")
		(net "M_C_CPU0_SB_DQ<20>")
	)
	(segment
		(start 276.469094 -207.091788)
		(end 274.40001 -207.091788)
		(width 0.1016)
		(layer "F.Cu")
		(net "M_C_CPU0_SB_DQ<20>")
	)
	(segment
		(start 273.37258 -207.29321)
		(end 273.37258 -207.58277)
		(width 0.20066)
		(layer "F.Cu")
		(net "M_C_CPU0_SB_DQ<20>")
	)
	(segment
		(start 273.19986 -207.75549)
		(end 272.741136 -207.75549)
		(width 0.20066)
		(layer "F.Cu")
		(net "M_C_CPU0_SB_DQ<20>")
	)
	(segment
		(start 278.711914 -207.51673)
		(end 277.342854 -207.51673)
		(width 0.20066)
		(layer "F.Cu")
		(net "M_C_CPU0_SB_DQ<20>")
	)
	(segment
		(start 279.816814 -207.51673)
		(end 278.711914 -207.51673)
		(width 0.20066)
		(layer "F.Cu")
		(net "M_C_CPU0_SB_DQ<20>")
	)
	(segment
		(start 274.40001 -207.091788)
		(end 274.152106 -207.091788)
		(width 0.101854)
		(layer "F.Cu")
		(net "M_C_CPU0_SB_DQ<20>")
	)
	(segment
		(start 272.741136 -207.75549)
		(end 272.502376 -207.51673)
		(width 0.20066)
		(layer "F.Cu")
		(net "M_C_CPU0_SB_DQ<20>")
	)
	(segment
		(start 320.11112 -221.77121)
		(end 315.48578 -210.60537)
		(width 0.18288)
		(layer "In4.Cu")
		(net "M_C_CPU0_SB_DQ<20>")
	)
	(segment
		(start 314.401454 -209.521044)
		(end 311.441084 -209.521044)
		(width 0.18288)
		(layer "In4.Cu")
		(net "M_C_CPU0_SB_DQ<20>")
	)
	(segment
		(start 280.422604 -208.12252)
		(end 279.816814 -207.51673)
		(width 0.18288)
		(layer "In4.Cu")
		(net "M_C_CPU0_SB_DQ<20>")
	)
	(segment
		(start 282.311602 -206.30134)
		(end 282.311602 -207.93964)
		(width 0.18288)
		(layer "In4.Cu")
		(net "M_C_CPU0_SB_DQ<20>")
	)
	(segment
		(start 311.441084 -209.521044)
		(end 310.736488 -208.816448)
		(width 0.18288)
		(layer "In4.Cu")
		(net "M_C_CPU0_SB_DQ<20>")
	)
	(segment
		(start 338.721954 -228.945694)
		(end 338.717382 -228.948234)
		(width 0.088646)
		(layer "In4.Cu")
		(net "M_C_CPU0_SB_DQ<20>")
	)
	(segment
		(start 282.494482 -206.11846)
		(end 282.311602 -206.30134)
		(width 0.18288)
		(layer "In4.Cu")
		(net "M_C_CPU0_SB_DQ<20>")
	)
	(segment
		(start 291.032692 -208.79181)
		(end 290.182554 -207.941672)
		(width 0.18288)
		(layer "In4.Cu")
		(net "M_C_CPU0_SB_DQ<20>")
	)
	(segment
		(start 283.492448 -208.12252)
		(end 283.185362 -208.12252)
		(width 0.18288)
		(layer "In4.Cu")
		(net "M_C_CPU0_SB_DQ<20>")
	)
	(segment
		(start 282.819602 -206.11846)
		(end 282.494482 -206.11846)
		(width 0.18288)
		(layer "In4.Cu")
		(net "M_C_CPU0_SB_DQ<20>")
	)
	(segment
		(start 315.48578 -210.60537)
		(end 314.401454 -209.521044)
		(width 0.18288)
		(layer "In4.Cu")
		(net "M_C_CPU0_SB_DQ<20>")
	)
	(segment
		(start 339.844634 -229.272846)
		(end 339.84438 -229.272592)
		(width 0.088646)
		(layer "In4.Cu")
		(net "M_C_CPU0_SB_DQ<20>")
	)
	(segment
		(start 300.281594 -207.941672)
		(end 298.453556 -207.941672)
		(width 0.18288)
		(layer "In4.Cu")
		(net "M_C_CPU0_SB_DQ<20>")
	)
	(segment
		(start 338.717382 -228.948234)
		(end 338.710016 -228.952552)
		(width 0.088646)
		(layer "In4.Cu")
		(net "M_C_CPU0_SB_DQ<20>")
	)
	(segment
		(start 330.648564 -227.855272)
		(end 326.195182 -227.855272)
		(width 0.18288)
		(layer "In4.Cu")
		(net "M_C_CPU0_SB_DQ<20>")
	)
	(segment
		(start 336.837782 -228.948234)
		(end 336.832194 -228.951536)
		(width 0.088646)
		(layer "In4.Cu")
		(net "M_C_CPU0_SB_DQ<20>")
	)
	(segment
		(start 310.736488 -208.816448)
		(end 301.15637 -208.816448)
		(width 0.18288)
		(layer "In4.Cu")
		(net "M_C_CPU0_SB_DQ<20>")
	)
	(segment
		(start 298.453556 -207.941672)
		(end 297.603418 -208.79181)
		(width 0.18288)
		(layer "In4.Cu")
		(net "M_C_CPU0_SB_DQ<20>")
	)
	(segment
		(start 282.311602 -207.93964)
		(end 282.128722 -208.12252)
		(width 0.18288)
		(layer "In4.Cu")
		(net "M_C_CPU0_SB_DQ<20>")
	)
	(segment
		(start 282.128722 -208.12252)
		(end 280.422604 -208.12252)
		(width 0.18288)
		(layer "In4.Cu")
		(net "M_C_CPU0_SB_DQ<20>")
	)
	(segment
		(start 283.002482 -207.93964)
		(end 283.002482 -206.30134)
		(width 0.18288)
		(layer "In4.Cu")
		(net "M_C_CPU0_SB_DQ<20>")
	)
	(segment
		(start 290.182554 -207.941672)
		(end 283.673296 -207.941672)
		(width 0.18288)
		(layer "In4.Cu")
		(net "M_C_CPU0_SB_DQ<20>")
	)
	(segment
		(start 297.603418 -208.79181)
		(end 291.032692 -208.79181)
		(width 0.18288)
		(layer "In4.Cu")
		(net "M_C_CPU0_SB_DQ<20>")
	)
	(segment
		(start 283.002482 -206.30134)
		(end 282.819602 -206.11846)
		(width 0.18288)
		(layer "In4.Cu")
		(net "M_C_CPU0_SB_DQ<20>")
	)
	(segment
		(start 331.584046 -228.799898)
		(end 331.584046 -228.495606)
		(width 0.088646)
		(layer "In4.Cu")
		(net "M_C_CPU0_SB_DQ<20>")
	)
	(segment
		(start 330.943712 -227.855272)
		(end 330.648564 -227.855272)
		(width 0.088646)
		(layer "In4.Cu")
		(net "M_C_CPU0_SB_DQ<20>")
	)
	(segment
		(start 339.488526 -229.177342)
		(end 339.092032 -228.948234)
		(width 0.088646)
		(layer "In4.Cu")
		(net "M_C_CPU0_SB_DQ<20>")
	)
	(segment
		(start 336.842354 -228.945694)
		(end 336.837782 -228.948234)
		(width 0.088646)
		(layer "In4.Cu")
		(net "M_C_CPU0_SB_DQ<20>")
	)
	(segment
		(start 331.80274 -229.018592)
		(end 331.584046 -228.799898)
		(width 0.088646)
		(layer "In4.Cu")
		(net "M_C_CPU0_SB_DQ<20>")
	)
	(segment
		(start 332.139036 -228.948488)
		(end 332.017624 -229.018592)
		(width 0.088646)
		(layer "In4.Cu")
		(net "M_C_CPU0_SB_DQ<20>")
	)
	(segment
		(start 283.185362 -208.12252)
		(end 283.002482 -207.93964)
		(width 0.18288)
		(layer "In4.Cu")
		(net "M_C_CPU0_SB_DQ<20>")
	)
	(segment
		(start 337.777582 -228.948234)
		(end 337.770216 -228.952552)
		(width 0.088646)
		(layer "In4.Cu")
		(net "M_C_CPU0_SB_DQ<20>")
	)
	(segment
		(start 331.584046 -228.495606)
		(end 330.943712 -227.855272)
		(width 0.088646)
		(layer "In4.Cu")
		(net "M_C_CPU0_SB_DQ<20>")
	)
	(segment
		(start 283.673296 -207.941672)
		(end 283.492448 -208.12252)
		(width 0.18288)
		(layer "In4.Cu")
		(net "M_C_CPU0_SB_DQ<20>")
	)
	(segment
		(start 326.195182 -227.855272)
		(end 320.11112 -221.77121)
		(width 0.18288)
		(layer "In4.Cu")
		(net "M_C_CPU0_SB_DQ<20>")
	)
	(segment
		(start 332.017624 -229.018592)
		(end 331.80274 -229.018592)
		(width 0.088646)
		(layer "In4.Cu")
		(net "M_C_CPU0_SB_DQ<20>")
	)
	(segment
		(start 301.15637 -208.816448)
		(end 300.281594 -207.941672)
		(width 0.18288)
		(layer "In4.Cu")
		(net "M_C_CPU0_SB_DQ<20>")
	)
	(segment
		(start 335.897982 -228.948234)
		(end 335.892902 -228.951282)
		(width 0.088646)
		(layer "In4.Cu")
		(net "M_C_CPU0_SB_DQ<20>")
	)
	(segment
		(start 337.782154 -228.945694)
		(end 337.777582 -228.948234)
		(width 0.088646)
		(layer "In4.Cu")
		(net "M_C_CPU0_SB_DQ<20>")
	)
	(arc
		(start 337.770216 -228.952552)
		(mid 337.490755 -229.024021)
		(end 337.212432 -228.948234)
		(width 0.088646)
		(layer "In4.Cu")
		(net "M_C_CPU0_SB_DQ<20>")
	)
	(arc
		(start 336.272632 -228.948234)
		(mid 336.085324 -228.898125)
		(end 335.897982 -228.948234)
		(width 0.088646)
		(layer "In4.Cu")
		(net "M_C_CPU0_SB_DQ<20>")
	)
	(arc
		(start 337.212432 -228.948234)
		(mid 337.027738 -228.898133)
		(end 336.842354 -228.945694)
		(width 0.088646)
		(layer "In4.Cu")
		(net "M_C_CPU0_SB_DQ<20>")
	)
	(arc
		(start 336.832194 -228.951536)
		(mid 336.551979 -229.02401)
		(end 336.272632 -228.948234)
		(width 0.088646)
		(layer "In4.Cu")
		(net "M_C_CPU0_SB_DQ<20>")
	)
	(arc
		(start 333.078836 -228.948488)
		(mid 332.796134 -229.024264)
		(end 332.513432 -228.948488)
		(width 0.088646)
		(layer "In4.Cu")
		(net "M_C_CPU0_SB_DQ<20>")
	)
	(arc
		(start 339.84438 -229.272592)
		(mid 339.660176 -229.248409)
		(end 339.488526 -229.177342)
		(width 0.088646)
		(layer "In4.Cu")
		(net "M_C_CPU0_SB_DQ<20>")
	)
	(arc
		(start 335.892902 -228.951282)
		(mid 335.612492 -229.024166)
		(end 335.332832 -228.948488)
		(width 0.088646)
		(layer "In4.Cu")
		(net "M_C_CPU0_SB_DQ<20>")
	)
	(arc
		(start 339.092032 -228.948234)
		(mid 338.907338 -228.898133)
		(end 338.721954 -228.945694)
		(width 0.088646)
		(layer "In4.Cu")
		(net "M_C_CPU0_SB_DQ<20>")
	)
	(arc
		(start 334.393032 -228.948488)
		(mid 334.205834 -228.898345)
		(end 334.018636 -228.948488)
		(width 0.088646)
		(layer "In4.Cu")
		(net "M_C_CPU0_SB_DQ<20>")
	)
	(arc
		(start 334.958436 -228.948488)
		(mid 334.675734 -229.024264)
		(end 334.393032 -228.948488)
		(width 0.088646)
		(layer "In4.Cu")
		(net "M_C_CPU0_SB_DQ<20>")
	)
	(arc
		(start 338.710016 -228.952552)
		(mid 338.430555 -229.024021)
		(end 338.152232 -228.948234)
		(width 0.088646)
		(layer "In4.Cu")
		(net "M_C_CPU0_SB_DQ<20>")
	)
	(arc
		(start 335.332832 -228.948488)
		(mid 335.145634 -228.898345)
		(end 334.958436 -228.948488)
		(width 0.088646)
		(layer "In4.Cu")
		(net "M_C_CPU0_SB_DQ<20>")
	)
	(arc
		(start 333.453232 -228.948488)
		(mid 333.266034 -228.898345)
		(end 333.078836 -228.948488)
		(width 0.088646)
		(layer "In4.Cu")
		(net "M_C_CPU0_SB_DQ<20>")
	)
	(arc
		(start 332.513432 -228.948488)
		(mid 332.326234 -228.898345)
		(end 332.139036 -228.948488)
		(width 0.088646)
		(layer "In4.Cu")
		(net "M_C_CPU0_SB_DQ<20>")
	)
	(arc
		(start 338.152232 -228.948234)
		(mid 337.967538 -228.898133)
		(end 337.782154 -228.945694)
		(width 0.088646)
		(layer "In4.Cu")
		(net "M_C_CPU0_SB_DQ<20>")
	)
	(arc
		(start 334.018636 -228.948488)
		(mid 333.735934 -229.024264)
		(end 333.453232 -228.948488)
		(width 0.088646)
		(layer "In4.Cu")
		(net "M_C_CPU0_SB_DQ<20>")
	)
	(segment
		(start 276.138386 -230.041704)
		(end 274.152868 -230.041704)
		(width 0.1016)
		(layer "F.Cu")
		(net "M_C_CPU0_SB_DQ<1>")
	)
	(segment
		(start 272.713704 -230.677974)
		(end 272.502376 -230.466646)
		(width 0.20066)
		(layer "F.Cu")
		(net "M_C_CPU0_SB_DQ<1>")
	)
	(segment
		(start 279.816814 -230.466646)
		(end 278.711914 -230.466646)
		(width 0.20066)
		(layer "F.Cu")
		(net "M_C_CPU0_SB_DQ<1>")
	)
	(segment
		(start 272.502376 -230.466646)
		(end 271.168114 -230.466646)
		(width 0.20066)
		(layer "F.Cu")
		(net "M_C_CPU0_SB_DQ<1>")
	)
	(segment
		(start 273.37258 -230.523542)
		(end 273.218148 -230.677974)
		(width 0.20066)
		(layer "F.Cu")
		(net "M_C_CPU0_SB_DQ<1>")
	)
	(segment
		(start 278.711914 -230.466646)
		(end 277.072598 -230.466646)
		(width 0.20066)
		(layer "F.Cu")
		(net "M_C_CPU0_SB_DQ<1>")
	)
	(segment
		(start 273.218148 -230.677974)
		(end 272.713704 -230.677974)
		(width 0.20066)
		(layer "F.Cu")
		(net "M_C_CPU0_SB_DQ<1>")
	)
	(segment
		(start 273.53514 -230.032814)
		(end 273.37258 -230.195374)
		(width 0.20066)
		(layer "F.Cu")
		(net "M_C_CPU0_SB_DQ<1>")
	)
	(segment
		(start 276.647656 -230.041704)
		(end 276.469094 -230.041704)
		(width 0.20066)
		(layer "F.Cu")
		(net "M_C_CPU0_SB_DQ<1>")
	)
	(segment
		(start 273.37258 -230.195374)
		(end 273.37258 -230.523542)
		(width 0.20066)
		(layer "F.Cu")
		(net "M_C_CPU0_SB_DQ<1>")
	)
	(segment
		(start 343.13368 -243.644674)
		(end 343.13368 -243.108988)
		(width 0.20066)
		(layer "F.Cu")
		(net "M_C_CPU0_SB_DQ<1>")
	)
	(segment
		(start 276.469094 -230.041704)
		(end 276.138386 -230.041704)
		(width 0.101854)
		(layer "F.Cu")
		(net "M_C_CPU0_SB_DQ<1>")
	)
	(segment
		(start 277.072598 -230.466646)
		(end 276.647656 -230.041704)
		(width 0.20066)
		(layer "F.Cu")
		(net "M_C_CPU0_SB_DQ<1>")
	)
	(segment
		(start 343.133934 -243.644928)
		(end 343.13368 -243.644674)
		(width 0.20066)
		(layer "F.Cu")
		(net "M_C_CPU0_SB_DQ<1>")
	)
	(segment
		(start 274.152868 -230.041704)
		(end 274.143978 -230.032814)
		(width 0.1016)
		(layer "F.Cu")
		(net "M_C_CPU0_SB_DQ<1>")
	)
	(segment
		(start 274.143978 -230.032814)
		(end 273.53514 -230.032814)
		(width 0.20066)
		(layer "F.Cu")
		(net "M_C_CPU0_SB_DQ<1>")
	)
	(segment
		(start 333.078582 -243.598446)
		(end 333.06385 -243.607082)
		(width 0.088646)
		(layer "In6.Cu")
		(net "M_C_CPU0_SB_DQ<1>")
	)
	(segment
		(start 280.93289 -230.891842)
		(end 280.24201 -230.891842)
		(width 0.18288)
		(layer "In6.Cu")
		(net "M_C_CPU0_SB_DQ<1>")
	)
	(segment
		(start 335.898236 -243.598446)
		(end 335.887822 -243.604542)
		(width 0.088646)
		(layer "In6.Cu")
		(net "M_C_CPU0_SB_DQ<1>")
	)
	(segment
		(start 331.699108 -243.437918)
		(end 331.029564 -243.437918)
		(width 0.088646)
		(layer "In6.Cu")
		(net "M_C_CPU0_SB_DQ<1>")
	)
	(segment
		(start 286.56407 -231.364282)
		(end 285.994094 -231.364282)
		(width 0.18288)
		(layer "In6.Cu")
		(net "M_C_CPU0_SB_DQ<1>")
	)
	(segment
		(start 342.580976 -243.536978)
		(end 342.476582 -243.598446)
		(width 0.088646)
		(layer "In6.Cu")
		(net "M_C_CPU0_SB_DQ<1>")
	)
	(segment
		(start 282.31465 -230.891842)
		(end 281.98953 -230.891842)
		(width 0.18288)
		(layer "In6.Cu")
		(net "M_C_CPU0_SB_DQ<1>")
	)
	(segment
		(start 334.018382 -243.598446)
		(end 334.00365 -243.607082)
		(width 0.088646)
		(layer "In6.Cu")
		(net "M_C_CPU0_SB_DQ<1>")
	)
	(segment
		(start 281.98953 -230.891842)
		(end 281.80665 -231.074722)
		(width 0.18288)
		(layer "In6.Cu")
		(net "M_C_CPU0_SB_DQ<1>")
	)
	(segment
		(start 340.602824 -243.595144)
		(end 340.59114 -243.601748)
		(width 0.088646)
		(layer "In6.Cu")
		(net "M_C_CPU0_SB_DQ<1>")
	)
	(segment
		(start 297.787822 -235.991654)
		(end 296.937938 -235.14177)
		(width 0.18288)
		(layer "In6.Cu")
		(net "M_C_CPU0_SB_DQ<1>")
	)
	(segment
		(start 318.760094 -242.432332)
		(end 314.928504 -238.600742)
		(width 0.18288)
		(layer "In6.Cu")
		(net "M_C_CPU0_SB_DQ<1>")
	)
	(segment
		(start 329.773534 -242.432332)
		(end 318.760094 -242.432332)
		(width 0.18288)
		(layer "In6.Cu")
		(net "M_C_CPU0_SB_DQ<1>")
	)
	(segment
		(start 296.937938 -235.14177)
		(end 291.953696 -235.14177)
		(width 0.18288)
		(layer "In6.Cu")
		(net "M_C_CPU0_SB_DQ<1>")
	)
	(segment
		(start 283.18841 -231.48544)
		(end 283.00553 -231.66832)
		(width 0.18288)
		(layer "In6.Cu")
		(net "M_C_CPU0_SB_DQ<1>")
	)
	(segment
		(start 312.076084 -237.367826)
		(end 307.336698 -237.367826)
		(width 0.18288)
		(layer "In6.Cu")
		(net "M_C_CPU0_SB_DQ<1>")
	)
	(segment
		(start 287.078674 -231.878886)
		(end 286.56407 -231.364282)
		(width 0.18288)
		(layer "In6.Cu")
		(net "M_C_CPU0_SB_DQ<1>")
	)
	(segment
		(start 336.843624 -243.595144)
		(end 336.837782 -243.598446)
		(width 0.088646)
		(layer "In6.Cu")
		(net "M_C_CPU0_SB_DQ<1>")
	)
	(segment
		(start 332.04912 -243.650262)
		(end 331.911452 -243.650262)
		(width 0.088646)
		(layer "In6.Cu")
		(net "M_C_CPU0_SB_DQ<1>")
	)
	(segment
		(start 283.18841 -231.074722)
		(end 283.18841 -231.48544)
		(width 0.18288)
		(layer "In6.Cu")
		(net "M_C_CPU0_SB_DQ<1>")
	)
	(segment
		(start 314.928504 -238.600742)
		(end 313.309 -238.600742)
		(width 0.18288)
		(layer "In6.Cu")
		(net "M_C_CPU0_SB_DQ<1>")
	)
	(segment
		(start 307.336698 -237.367826)
		(end 306.52339 -236.554518)
		(width 0.18288)
		(layer "In6.Cu")
		(net "M_C_CPU0_SB_DQ<1>")
	)
	(segment
		(start 289.249358 -233.27995)
		(end 287.848294 -231.878886)
		(width 0.18288)
		(layer "In6.Cu")
		(net "M_C_CPU0_SB_DQ<1>")
	)
	(segment
		(start 341.542624 -243.595144)
		(end 341.53094 -243.601748)
		(width 0.088646)
		(layer "In6.Cu")
		(net "M_C_CPU0_SB_DQ<1>")
	)
	(segment
		(start 280.24201 -230.891842)
		(end 279.816814 -230.466646)
		(width 0.18288)
		(layer "In6.Cu")
		(net "M_C_CPU0_SB_DQ<1>")
	)
	(segment
		(start 281.11577 -231.48544)
		(end 281.11577 -231.074722)
		(width 0.18288)
		(layer "In6.Cu")
		(net "M_C_CPU0_SB_DQ<1>")
	)
	(segment
		(start 282.49753 -231.074722)
		(end 282.31465 -230.891842)
		(width 0.18288)
		(layer "In6.Cu")
		(net "M_C_CPU0_SB_DQ<1>")
	)
	(segment
		(start 287.848294 -231.878886)
		(end 287.078674 -231.878886)
		(width 0.18288)
		(layer "In6.Cu")
		(net "M_C_CPU0_SB_DQ<1>")
	)
	(segment
		(start 313.309 -238.600742)
		(end 312.076084 -237.367826)
		(width 0.18288)
		(layer "In6.Cu")
		(net "M_C_CPU0_SB_DQ<1>")
	)
	(segment
		(start 285.521654 -230.891842)
		(end 283.37129 -230.891842)
		(width 0.18288)
		(layer "In6.Cu")
		(net "M_C_CPU0_SB_DQ<1>")
	)
	(segment
		(start 336.837782 -243.598446)
		(end 336.83321 -243.600986)
		(width 0.088646)
		(layer "In6.Cu")
		(net "M_C_CPU0_SB_DQ<1>")
	)
	(segment
		(start 281.62377 -231.66832)
		(end 281.29865 -231.66832)
		(width 0.18288)
		(layer "In6.Cu")
		(net "M_C_CPU0_SB_DQ<1>")
	)
	(segment
		(start 281.29865 -231.66832)
		(end 281.11577 -231.48544)
		(width 0.18288)
		(layer "In6.Cu")
		(net "M_C_CPU0_SB_DQ<1>")
	)
	(segment
		(start 302.749204 -235.705142)
		(end 299.944536 -235.705142)
		(width 0.18288)
		(layer "In6.Cu")
		(net "M_C_CPU0_SB_DQ<1>")
	)
	(segment
		(start 283.00553 -231.66832)
		(end 282.68041 -231.66832)
		(width 0.18288)
		(layer "In6.Cu")
		(net "M_C_CPU0_SB_DQ<1>")
	)
	(segment
		(start 342.476582 -243.598446)
		(end 342.47074 -243.601748)
		(width 0.088646)
		(layer "In6.Cu")
		(net "M_C_CPU0_SB_DQ<1>")
	)
	(segment
		(start 299.944536 -235.705142)
		(end 299.658024 -235.991654)
		(width 0.18288)
		(layer "In6.Cu")
		(net "M_C_CPU0_SB_DQ<1>")
	)
	(segment
		(start 282.68041 -231.66832)
		(end 282.49753 -231.48544)
		(width 0.18288)
		(layer "In6.Cu")
		(net "M_C_CPU0_SB_DQ<1>")
	)
	(segment
		(start 299.658024 -235.991654)
		(end 297.787822 -235.991654)
		(width 0.18288)
		(layer "In6.Cu")
		(net "M_C_CPU0_SB_DQ<1>")
	)
	(segment
		(start 332.138782 -243.598446)
		(end 332.04912 -243.650262)
		(width 0.088646)
		(layer "In6.Cu")
		(net "M_C_CPU0_SB_DQ<1>")
	)
	(segment
		(start 330.77912 -243.437918)
		(end 329.773534 -242.432332)
		(width 0.18288)
		(layer "In6.Cu")
		(net "M_C_CPU0_SB_DQ<1>")
	)
	(segment
		(start 343.13368 -243.108988)
		(end 343.133426 -243.108988)
		(width 0.088646)
		(layer "In6.Cu")
		(net "M_C_CPU0_SB_DQ<1>")
	)
	(segment
		(start 334.958182 -243.598446)
		(end 334.94345 -243.607082)
		(width 0.088646)
		(layer "In6.Cu")
		(net "M_C_CPU0_SB_DQ<1>")
	)
	(segment
		(start 285.994094 -231.364282)
		(end 285.521654 -230.891842)
		(width 0.18288)
		(layer "In6.Cu")
		(net "M_C_CPU0_SB_DQ<1>")
	)
	(segment
		(start 339.663024 -243.595144)
		(end 339.65134 -243.601748)
		(width 0.088646)
		(layer "In6.Cu")
		(net "M_C_CPU0_SB_DQ<1>")
	)
	(segment
		(start 331.911452 -243.650262)
		(end 331.699108 -243.437918)
		(width 0.088646)
		(layer "In6.Cu")
		(net "M_C_CPU0_SB_DQ<1>")
	)
	(segment
		(start 283.37129 -230.891842)
		(end 283.18841 -231.074722)
		(width 0.18288)
		(layer "In6.Cu")
		(net "M_C_CPU0_SB_DQ<1>")
	)
	(segment
		(start 282.49753 -231.48544)
		(end 282.49753 -231.074722)
		(width 0.18288)
		(layer "In6.Cu")
		(net "M_C_CPU0_SB_DQ<1>")
	)
	(segment
		(start 337.783424 -243.595144)
		(end 337.77174 -243.601748)
		(width 0.088646)
		(layer "In6.Cu")
		(net "M_C_CPU0_SB_DQ<1>")
	)
	(segment
		(start 338.723224 -243.595144)
		(end 338.71154 -243.601748)
		(width 0.088646)
		(layer "In6.Cu")
		(net "M_C_CPU0_SB_DQ<1>")
	)
	(segment
		(start 281.11577 -231.074722)
		(end 280.93289 -230.891842)
		(width 0.18288)
		(layer "In6.Cu")
		(net "M_C_CPU0_SB_DQ<1>")
	)
	(segment
		(start 281.80665 -231.48544)
		(end 281.62377 -231.66832)
		(width 0.18288)
		(layer "In6.Cu")
		(net "M_C_CPU0_SB_DQ<1>")
	)
	(segment
		(start 291.953696 -235.14177)
		(end 290.091876 -233.27995)
		(width 0.18288)
		(layer "In6.Cu")
		(net "M_C_CPU0_SB_DQ<1>")
	)
	(segment
		(start 290.091876 -233.27995)
		(end 289.249358 -233.27995)
		(width 0.18288)
		(layer "In6.Cu")
		(net "M_C_CPU0_SB_DQ<1>")
	)
	(segment
		(start 281.80665 -231.074722)
		(end 281.80665 -231.48544)
		(width 0.18288)
		(layer "In6.Cu")
		(net "M_C_CPU0_SB_DQ<1>")
	)
	(segment
		(start 306.52339 -236.554518)
		(end 303.59858 -236.554518)
		(width 0.18288)
		(layer "In6.Cu")
		(net "M_C_CPU0_SB_DQ<1>")
	)
	(segment
		(start 331.029564 -243.437918)
		(end 330.77912 -243.437918)
		(width 0.18288)
		(layer "In6.Cu")
		(net "M_C_CPU0_SB_DQ<1>")
	)
	(segment
		(start 303.59858 -236.554518)
		(end 302.749204 -235.705142)
		(width 0.18288)
		(layer "In6.Cu")
		(net "M_C_CPU0_SB_DQ<1>")
	)
	(arc
		(start 338.152232 -243.598446)
		(mid 337.968278 -243.548317)
		(end 337.783424 -243.595144)
		(width 0.088646)
		(layer "In6.Cu")
		(net "M_C_CPU0_SB_DQ<1>")
	)
	(arc
		(start 338.71154 -243.601748)
		(mid 338.431435 -243.67419)
		(end 338.152232 -243.598446)
		(width 0.088646)
		(layer "In6.Cu")
		(net "M_C_CPU0_SB_DQ<1>")
	)
	(arc
		(start 333.06385 -243.607082)
		(mid 332.787375 -243.674402)
		(end 332.513178 -243.598446)
		(width 0.088646)
		(layer "In6.Cu")
		(net "M_C_CPU0_SB_DQ<1>")
	)
	(arc
		(start 340.59114 -243.601748)
		(mid 340.311035 -243.67419)
		(end 340.031832 -243.598446)
		(width 0.088646)
		(layer "In6.Cu")
		(net "M_C_CPU0_SB_DQ<1>")
	)
	(arc
		(start 339.092032 -243.598446)
		(mid 338.908078 -243.548317)
		(end 338.723224 -243.595144)
		(width 0.088646)
		(layer "In6.Cu")
		(net "M_C_CPU0_SB_DQ<1>")
	)
	(arc
		(start 333.452978 -243.598446)
		(mid 333.26578 -243.548303)
		(end 333.078582 -243.598446)
		(width 0.088646)
		(layer "In6.Cu")
		(net "M_C_CPU0_SB_DQ<1>")
	)
	(arc
		(start 336.272632 -243.598446)
		(mid 336.085434 -243.548303)
		(end 335.898236 -243.598446)
		(width 0.088646)
		(layer "In6.Cu")
		(net "M_C_CPU0_SB_DQ<1>")
	)
	(arc
		(start 334.00365 -243.607082)
		(mid 333.727175 -243.674402)
		(end 333.452978 -243.598446)
		(width 0.088646)
		(layer "In6.Cu")
		(net "M_C_CPU0_SB_DQ<1>")
	)
	(arc
		(start 334.94345 -243.607082)
		(mid 334.666975 -243.674402)
		(end 334.392778 -243.598446)
		(width 0.088646)
		(layer "In6.Cu")
		(net "M_C_CPU0_SB_DQ<1>")
	)
	(arc
		(start 337.77174 -243.601748)
		(mid 337.491635 -243.67419)
		(end 337.212432 -243.598446)
		(width 0.088646)
		(layer "In6.Cu")
		(net "M_C_CPU0_SB_DQ<1>")
	)
	(arc
		(start 340.971632 -243.598446)
		(mid 340.787678 -243.548317)
		(end 340.602824 -243.595144)
		(width 0.088646)
		(layer "In6.Cu")
		(net "M_C_CPU0_SB_DQ<1>")
	)
	(arc
		(start 339.65134 -243.601748)
		(mid 339.371235 -243.67419)
		(end 339.092032 -243.598446)
		(width 0.088646)
		(layer "In6.Cu")
		(net "M_C_CPU0_SB_DQ<1>")
	)
	(arc
		(start 336.83321 -243.600986)
		(mid 336.552575 -243.674154)
		(end 336.272632 -243.598446)
		(width 0.088646)
		(layer "In6.Cu")
		(net "M_C_CPU0_SB_DQ<1>")
	)
	(arc
		(start 341.53094 -243.601748)
		(mid 341.250835 -243.67419)
		(end 340.971632 -243.598446)
		(width 0.088646)
		(layer "In6.Cu")
		(net "M_C_CPU0_SB_DQ<1>")
	)
	(arc
		(start 332.513178 -243.598446)
		(mid 332.32598 -243.548303)
		(end 332.138782 -243.598446)
		(width 0.088646)
		(layer "In6.Cu")
		(net "M_C_CPU0_SB_DQ<1>")
	)
	(arc
		(start 341.911432 -243.598446)
		(mid 341.727478 -243.548317)
		(end 341.542624 -243.595144)
		(width 0.088646)
		(layer "In6.Cu")
		(net "M_C_CPU0_SB_DQ<1>")
	)
	(arc
		(start 343.133426 -243.108988)
		(mid 342.870735 -243.340452)
		(end 342.580976 -243.536978)
		(width 0.088646)
		(layer "In6.Cu")
		(net "M_C_CPU0_SB_DQ<1>")
	)
	(arc
		(start 335.887822 -243.604542)
		(mid 335.60939 -243.674388)
		(end 335.332578 -243.598446)
		(width 0.088646)
		(layer "In6.Cu")
		(net "M_C_CPU0_SB_DQ<1>")
	)
	(arc
		(start 337.212432 -243.598446)
		(mid 337.028478 -243.548317)
		(end 336.843624 -243.595144)
		(width 0.088646)
		(layer "In6.Cu")
		(net "M_C_CPU0_SB_DQ<1>")
	)
	(arc
		(start 334.392778 -243.598446)
		(mid 334.20558 -243.548303)
		(end 334.018382 -243.598446)
		(width 0.088646)
		(layer "In6.Cu")
		(net "M_C_CPU0_SB_DQ<1>")
	)
	(arc
		(start 340.031832 -243.598446)
		(mid 339.847878 -243.548317)
		(end 339.663024 -243.595144)
		(width 0.088646)
		(layer "In6.Cu")
		(net "M_C_CPU0_SB_DQ<1>")
	)
	(arc
		(start 335.332578 -243.598446)
		(mid 335.14538 -243.548303)
		(end 334.958182 -243.598446)
		(width 0.088646)
		(layer "In6.Cu")
		(net "M_C_CPU0_SB_DQ<1>")
	)
	(arc
		(start 342.47074 -243.601748)
		(mid 342.190635 -243.67419)
		(end 341.911432 -243.598446)
		(width 0.088646)
		(layer "In6.Cu")
		(net "M_C_CPU0_SB_DQ<1>")
	)
	(segment
		(start 277.091394 -211.042758)
		(end 276.96541 -210.916774)
		(width 0.20066)
		(layer "F.Cu")
		(net "M_C_CPU0_SB_DQ<19>")
	)
	(segment
		(start 280.606246 -211.04098)
		(end 280.606246 -211.192618)
		(width 0.20066)
		(layer "F.Cu")
		(net "M_C_CPU0_SB_DQ<19>")
	)
	(segment
		(start 281.788362 -211.124292)
		(end 281.34183 -211.124292)
		(width 0.20066)
		(layer "F.Cu")
		(net "M_C_CPU0_SB_DQ<19>")
	)
	(segment
		(start 277.233888 -211.35594)
		(end 277.091394 -211.213446)
		(width 0.20066)
		(layer "F.Cu")
		(net "M_C_CPU0_SB_DQ<19>")
	)
	(segment
		(start 341.72398 -231.436418)
		(end 341.724234 -231.436164)
		(width 0.20066)
		(layer "F.Cu")
		(net "M_C_CPU0_SB_DQ<19>")
	)
	(segment
		(start 280.457148 -211.341716)
		(end 279.912826 -211.341716)
		(width 0.20066)
		(layer "F.Cu")
		(net "M_C_CPU0_SB_DQ<19>")
	)
	(segment
		(start 282.811982 -210.916774)
		(end 281.99588 -210.916774)
		(width 0.20066)
		(layer "F.Cu")
		(net "M_C_CPU0_SB_DQ<19>")
	)
	(segment
		(start 277.839932 -211.341716)
		(end 277.601934 -211.341716)
		(width 0.101854)
		(layer "F.Cu")
		(net "M_C_CPU0_SB_DQ<19>")
	)
	(segment
		(start 341.724234 -231.436164)
		(end 341.724234 -230.900478)
		(width 0.20066)
		(layer "F.Cu")
		(net "M_C_CPU0_SB_DQ<19>")
	)
	(segment
		(start 280.606246 -211.192618)
		(end 280.457148 -211.341716)
		(width 0.20066)
		(layer "F.Cu")
		(net "M_C_CPU0_SB_DQ<19>")
	)
	(segment
		(start 277.601934 -211.341716)
		(end 277.58771 -211.35594)
		(width 0.101854)
		(layer "F.Cu")
		(net "M_C_CPU0_SB_DQ<19>")
	)
	(segment
		(start 281.129994 -210.912456)
		(end 280.73477 -210.912456)
		(width 0.20066)
		(layer "F.Cu")
		(net "M_C_CPU0_SB_DQ<19>")
	)
	(segment
		(start 280.73477 -210.912456)
		(end 280.606246 -211.04098)
		(width 0.20066)
		(layer "F.Cu")
		(net "M_C_CPU0_SB_DQ<19>")
	)
	(segment
		(start 281.34183 -211.124292)
		(end 281.129994 -210.912456)
		(width 0.20066)
		(layer "F.Cu")
		(net "M_C_CPU0_SB_DQ<19>")
	)
	(segment
		(start 281.99588 -210.916774)
		(end 281.788362 -211.124292)
		(width 0.20066)
		(layer "F.Cu")
		(net "M_C_CPU0_SB_DQ<19>")
	)
	(segment
		(start 279.912826 -211.341716)
		(end 277.839932 -211.341716)
		(width 0.1016)
		(layer "F.Cu")
		(net "M_C_CPU0_SB_DQ<19>")
	)
	(segment
		(start 277.58771 -211.35594)
		(end 277.233888 -211.35594)
		(width 0.20066)
		(layer "F.Cu")
		(net "M_C_CPU0_SB_DQ<19>")
	)
	(segment
		(start 276.96541 -210.916774)
		(end 275.268182 -210.916774)
		(width 0.20066)
		(layer "F.Cu")
		(net "M_C_CPU0_SB_DQ<19>")
	)
	(segment
		(start 277.091394 -211.213446)
		(end 277.091394 -211.042758)
		(width 0.20066)
		(layer "F.Cu")
		(net "M_C_CPU0_SB_DQ<19>")
	)
	(segment
		(start 283.916882 -210.916774)
		(end 282.811982 -210.916774)
		(width 0.20066)
		(layer "F.Cu")
		(net "M_C_CPU0_SB_DQ<19>")
	)
	(segment
		(start 287.039558 -211.527644)
		(end 286.629094 -211.527644)
		(width 0.18288)
		(layer "In4.Cu")
		(net "M_C_CPU0_SB_DQ<19>")
	)
	(segment
		(start 291.389816 -212.435948)
		(end 290.98875 -212.435948)
		(width 0.18288)
		(layer "In4.Cu")
		(net "M_C_CPU0_SB_DQ<19>")
	)
	(segment
		(start 290.13531 -211.889848)
		(end 290.13531 -212.253322)
		(width 0.18288)
		(layer "In4.Cu")
		(net "M_C_CPU0_SB_DQ<19>")
	)
	(segment
		(start 309.20182 -212.77961)
		(end 309.01894 -212.59673)
		(width 0.18288)
		(layer "In4.Cu")
		(net "M_C_CPU0_SB_DQ<19>")
	)
	(segment
		(start 337.777582 -231.22509)
		(end 337.770216 -231.220772)
		(width 0.088646)
		(layer "In4.Cu")
		(net "M_C_CPU0_SB_DQ<19>")
	)
	(segment
		(start 308.32806 -213.226142)
		(end 307.33365 -213.226142)
		(width 0.18288)
		(layer "In4.Cu")
		(net "M_C_CPU0_SB_DQ<19>")
	)
	(segment
		(start 309.01894 -212.59673)
		(end 308.69382 -212.59673)
		(width 0.18288)
		(layer "In4.Cu")
		(net "M_C_CPU0_SB_DQ<19>")
	)
	(segment
		(start 341.724234 -230.900478)
		(end 341.72398 -230.900478)
		(width 0.088646)
		(layer "In4.Cu")
		(net "M_C_CPU0_SB_DQ<19>")
	)
	(segment
		(start 305.212496 -212.80628)
		(end 305.029616 -212.98916)
		(width 0.18288)
		(layer "In4.Cu")
		(net "M_C_CPU0_SB_DQ<19>")
	)
	(segment
		(start 308.51094 -213.043262)
		(end 308.32806 -213.226142)
		(width 0.18288)
		(layer "In4.Cu")
		(net "M_C_CPU0_SB_DQ<19>")
	)
	(segment
		(start 287.933638 -212.421724)
		(end 287.039558 -211.527644)
		(width 0.18288)
		(layer "In4.Cu")
		(net "M_C_CPU0_SB_DQ<19>")
	)
	(segment
		(start 285.755334 -210.919568)
		(end 285.755334 -211.344764)
		(width 0.18288)
		(layer "In4.Cu")
		(net "M_C_CPU0_SB_DQ<19>")
	)
	(segment
		(start 305.029616 -212.98916)
		(end 304.704496 -212.98916)
		(width 0.18288)
		(layer "In4.Cu")
		(net "M_C_CPU0_SB_DQ<19>")
	)
	(segment
		(start 305.903376 -212.80628)
		(end 305.903376 -211.850478)
		(width 0.18288)
		(layer "In4.Cu")
		(net "M_C_CPU0_SB_DQ<19>")
	)
	(segment
		(start 305.720496 -211.667598)
		(end 305.395376 -211.667598)
		(width 0.18288)
		(layer "In4.Cu")
		(net "M_C_CPU0_SB_DQ<19>")
	)
	(segment
		(start 290.13531 -212.253322)
		(end 289.966908 -212.421724)
		(width 0.18288)
		(layer "In4.Cu")
		(net "M_C_CPU0_SB_DQ<19>")
	)
	(segment
		(start 339.663024 -230.572818)
		(end 339.65134 -230.579422)
		(width 0.088646)
		(layer "In4.Cu")
		(net "M_C_CPU0_SB_DQ<19>")
	)
	(segment
		(start 337.782154 -231.22763)
		(end 337.777582 -231.22509)
		(width 0.088646)
		(layer "In4.Cu")
		(net "M_C_CPU0_SB_DQ<19>")
	)
	(segment
		(start 340.602824 -230.572818)
		(end 340.59114 -230.579422)
		(width 0.088646)
		(layer "In4.Cu")
		(net "M_C_CPU0_SB_DQ<19>")
	)
	(segment
		(start 309.3847 -213.226142)
		(end 309.20182 -213.043262)
		(width 0.18288)
		(layer "In4.Cu")
		(net "M_C_CPU0_SB_DQ<19>")
	)
	(segment
		(start 297.658028 -213.891622)
		(end 292.84549 -213.891622)
		(width 0.18288)
		(layer "In4.Cu")
		(net "M_C_CPU0_SB_DQ<19>")
	)
	(segment
		(start 335.897982 -231.22509)
		(end 335.898236 -231.224836)
		(width 0.088646)
		(layer "In4.Cu")
		(net "M_C_CPU0_SB_DQ<19>")
	)
	(segment
		(start 290.82873 -211.864448)
		(end 290.66871 -211.704428)
		(width 0.18288)
		(layer "In4.Cu")
		(net "M_C_CPU0_SB_DQ<19>")
	)
	(segment
		(start 286.629094 -211.527644)
		(end 286.446214 -211.344764)
		(width 0.18288)
		(layer "In4.Cu")
		(net "M_C_CPU0_SB_DQ<19>")
	)
	(segment
		(start 304.521616 -212.458554)
		(end 304.338736 -212.275674)
		(width 0.18288)
		(layer "In4.Cu")
		(net "M_C_CPU0_SB_DQ<19>")
	)
	(segment
		(start 303.647856 -212.98916)
		(end 302.992028 -212.98916)
		(width 0.18288)
		(layer "In4.Cu")
		(net "M_C_CPU0_SB_DQ<19>")
	)
	(segment
		(start 298.507912 -213.041738)
		(end 297.658028 -213.891622)
		(width 0.18288)
		(layer "In4.Cu")
		(net "M_C_CPU0_SB_DQ<19>")
	)
	(segment
		(start 290.66871 -211.704428)
		(end 290.32073 -211.704428)
		(width 0.18288)
		(layer "In4.Cu")
		(net "M_C_CPU0_SB_DQ<19>")
	)
	(segment
		(start 304.521616 -212.80628)
		(end 304.521616 -212.458554)
		(width 0.18288)
		(layer "In4.Cu")
		(net "M_C_CPU0_SB_DQ<19>")
	)
	(segment
		(start 303.830736 -212.458554)
		(end 303.830736 -212.80628)
		(width 0.18288)
		(layer "In4.Cu")
		(net "M_C_CPU0_SB_DQ<19>")
	)
	(segment
		(start 286.263334 -210.736688)
		(end 285.938214 -210.736688)
		(width 0.18288)
		(layer "In4.Cu")
		(net "M_C_CPU0_SB_DQ<19>")
	)
	(segment
		(start 290.82873 -212.275928)
		(end 290.82873 -211.864448)
		(width 0.18288)
		(layer "In4.Cu")
		(net "M_C_CPU0_SB_DQ<19>")
	)
	(segment
		(start 303.830736 -212.80628)
		(end 303.647856 -212.98916)
		(width 0.18288)
		(layer "In4.Cu")
		(net "M_C_CPU0_SB_DQ<19>")
	)
	(segment
		(start 302.79975 -213.181438)
		(end 299.841158 -213.181438)
		(width 0.18288)
		(layer "In4.Cu")
		(net "M_C_CPU0_SB_DQ<19>")
	)
	(segment
		(start 331.010006 -229.981506)
		(end 330.648564 -229.981506)
		(width 0.088646)
		(layer "In4.Cu")
		(net "M_C_CPU0_SB_DQ<19>")
	)
	(segment
		(start 309.20182 -213.043262)
		(end 309.20182 -212.77961)
		(width 0.18288)
		(layer "In4.Cu")
		(net "M_C_CPU0_SB_DQ<19>")
	)
	(segment
		(start 308.69382 -212.59673)
		(end 308.51094 -212.77961)
		(width 0.18288)
		(layer "In4.Cu")
		(net "M_C_CPU0_SB_DQ<19>")
	)
	(segment
		(start 285.755334 -211.344764)
		(end 285.572454 -211.527644)
		(width 0.18288)
		(layer "In4.Cu")
		(net "M_C_CPU0_SB_DQ<19>")
	)
	(segment
		(start 302.992028 -212.98916)
		(end 302.79975 -213.181438)
		(width 0.18288)
		(layer "In4.Cu")
		(net "M_C_CPU0_SB_DQ<19>")
	)
	(segment
		(start 286.446214 -210.919568)
		(end 286.263334 -210.736688)
		(width 0.18288)
		(layer "In4.Cu")
		(net "M_C_CPU0_SB_DQ<19>")
	)
	(segment
		(start 331.91577 -230.88727)
		(end 331.010006 -229.981506)
		(width 0.088646)
		(layer "In4.Cu")
		(net "M_C_CPU0_SB_DQ<19>")
	)
	(segment
		(start 286.446214 -211.344764)
		(end 286.446214 -210.919568)
		(width 0.18288)
		(layer "In4.Cu")
		(net "M_C_CPU0_SB_DQ<19>")
	)
	(segment
		(start 307.096668 -212.98916)
		(end 306.086256 -212.98916)
		(width 0.18288)
		(layer "In4.Cu")
		(net "M_C_CPU0_SB_DQ<19>")
	)
	(segment
		(start 330.648564 -229.981506)
		(end 325.28891 -229.981506)
		(width 0.18288)
		(layer "In4.Cu")
		(net "M_C_CPU0_SB_DQ<19>")
	)
	(segment
		(start 306.086256 -212.98916)
		(end 305.903376 -212.80628)
		(width 0.18288)
		(layer "In4.Cu")
		(net "M_C_CPU0_SB_DQ<19>")
	)
	(segment
		(start 290.32073 -211.704428)
		(end 290.13531 -211.889848)
		(width 0.18288)
		(layer "In4.Cu")
		(net "M_C_CPU0_SB_DQ<19>")
	)
	(segment
		(start 307.33365 -213.226142)
		(end 307.096668 -212.98916)
		(width 0.18288)
		(layer "In4.Cu")
		(net "M_C_CPU0_SB_DQ<19>")
	)
	(segment
		(start 299.841158 -213.181438)
		(end 299.701458 -213.041738)
		(width 0.18288)
		(layer "In4.Cu")
		(net "M_C_CPU0_SB_DQ<19>")
	)
	(segment
		(start 299.701458 -213.041738)
		(end 298.507912 -213.041738)
		(width 0.18288)
		(layer "In4.Cu")
		(net "M_C_CPU0_SB_DQ<19>")
	)
	(segment
		(start 304.338736 -212.275674)
		(end 304.013616 -212.275674)
		(width 0.18288)
		(layer "In4.Cu")
		(net "M_C_CPU0_SB_DQ<19>")
	)
	(segment
		(start 290.98875 -212.435948)
		(end 290.82873 -212.275928)
		(width 0.18288)
		(layer "In4.Cu")
		(net "M_C_CPU0_SB_DQ<19>")
	)
	(segment
		(start 336.842354 -231.22763)
		(end 336.837782 -231.22509)
		(width 0.088646)
		(layer "In4.Cu")
		(net "M_C_CPU0_SB_DQ<19>")
	)
	(segment
		(start 284.527752 -211.527644)
		(end 283.916882 -210.916774)
		(width 0.18288)
		(layer "In4.Cu")
		(net "M_C_CPU0_SB_DQ<19>")
	)
	(segment
		(start 338.717382 -231.22509)
		(end 338.710016 -231.220772)
		(width 0.088646)
		(layer "In4.Cu")
		(net "M_C_CPU0_SB_DQ<19>")
	)
	(segment
		(start 339.433154 -230.792274)
		(end 339.367876 -230.950008)
		(width 0.088646)
		(layer "In4.Cu")
		(net "M_C_CPU0_SB_DQ<19>")
	)
	(segment
		(start 314.882276 -215.13292)
		(end 313.866022 -214.116666)
		(width 0.18288)
		(layer "In4.Cu")
		(net "M_C_CPU0_SB_DQ<19>")
	)
	(segment
		(start 331.91577 -231.00157)
		(end 331.91577 -230.88727)
		(width 0.088646)
		(layer "In4.Cu")
		(net "M_C_CPU0_SB_DQ<19>")
	)
	(segment
		(start 305.395376 -211.667598)
		(end 305.212496 -211.850478)
		(width 0.18288)
		(layer "In4.Cu")
		(net "M_C_CPU0_SB_DQ<19>")
	)
	(segment
		(start 332.139036 -231.224836)
		(end 331.91577 -231.00157)
		(width 0.088646)
		(layer "In4.Cu")
		(net "M_C_CPU0_SB_DQ<19>")
	)
	(segment
		(start 289.966908 -212.421724)
		(end 287.933638 -212.421724)
		(width 0.18288)
		(layer "In4.Cu")
		(net "M_C_CPU0_SB_DQ<19>")
	)
	(segment
		(start 285.572454 -211.527644)
		(end 284.527752 -211.527644)
		(width 0.18288)
		(layer "In4.Cu")
		(net "M_C_CPU0_SB_DQ<19>")
	)
	(segment
		(start 339.325966 -231.012492)
		(end 339.184488 -231.15397)
		(width 0.088646)
		(layer "In4.Cu")
		(net "M_C_CPU0_SB_DQ<19>")
	)
	(segment
		(start 305.903376 -211.850478)
		(end 305.720496 -211.667598)
		(width 0.18288)
		(layer "In4.Cu")
		(net "M_C_CPU0_SB_DQ<19>")
	)
	(segment
		(start 341.36838 -230.805228)
		(end 340.971632 -230.57612)
		(width 0.088646)
		(layer "In4.Cu")
		(net "M_C_CPU0_SB_DQ<19>")
	)
	(segment
		(start 313.866022 -214.116666)
		(end 311.782206 -214.116666)
		(width 0.18288)
		(layer "In4.Cu")
		(net "M_C_CPU0_SB_DQ<19>")
	)
	(segment
		(start 311.782206 -214.116666)
		(end 310.891682 -213.226142)
		(width 0.18288)
		(layer "In4.Cu")
		(net "M_C_CPU0_SB_DQ<19>")
	)
	(segment
		(start 292.84549 -213.891622)
		(end 291.389816 -212.435948)
		(width 0.18288)
		(layer "In4.Cu")
		(net "M_C_CPU0_SB_DQ<19>")
	)
	(segment
		(start 325.28891 -229.981506)
		(end 318.022986 -222.715582)
		(width 0.18288)
		(layer "In4.Cu")
		(net "M_C_CPU0_SB_DQ<19>")
	)
	(segment
		(start 305.212496 -211.850478)
		(end 305.212496 -212.80628)
		(width 0.18288)
		(layer "In4.Cu")
		(net "M_C_CPU0_SB_DQ<19>")
	)
	(segment
		(start 336.837782 -231.22509)
		(end 336.83321 -231.222296)
		(width 0.088646)
		(layer "In4.Cu")
		(net "M_C_CPU0_SB_DQ<19>")
	)
	(segment
		(start 318.022986 -222.715582)
		(end 314.882276 -215.13292)
		(width 0.18288)
		(layer "In4.Cu")
		(net "M_C_CPU0_SB_DQ<19>")
	)
	(segment
		(start 310.891682 -213.226142)
		(end 309.3847 -213.226142)
		(width 0.18288)
		(layer "In4.Cu")
		(net "M_C_CPU0_SB_DQ<19>")
	)
	(segment
		(start 304.013616 -212.275674)
		(end 303.830736 -212.458554)
		(width 0.18288)
		(layer "In4.Cu")
		(net "M_C_CPU0_SB_DQ<19>")
	)
	(segment
		(start 338.721954 -231.22763)
		(end 338.717382 -231.22509)
		(width 0.088646)
		(layer "In4.Cu")
		(net "M_C_CPU0_SB_DQ<19>")
	)
	(segment
		(start 304.704496 -212.98916)
		(end 304.521616 -212.80628)
		(width 0.18288)
		(layer "In4.Cu")
		(net "M_C_CPU0_SB_DQ<19>")
	)
	(segment
		(start 285.938214 -210.736688)
		(end 285.755334 -210.919568)
		(width 0.18288)
		(layer "In4.Cu")
		(net "M_C_CPU0_SB_DQ<19>")
	)
	(segment
		(start 308.51094 -212.77961)
		(end 308.51094 -213.043262)
		(width 0.18288)
		(layer "In4.Cu")
		(net "M_C_CPU0_SB_DQ<19>")
	)
	(arc
		(start 340.971632 -230.57612)
		(mid 340.787678 -230.525991)
		(end 340.602824 -230.572818)
		(width 0.088646)
		(layer "In4.Cu")
		(net "M_C_CPU0_SB_DQ<19>")
	)
	(arc
		(start 338.710016 -231.220772)
		(mid 338.430555 -231.149335)
		(end 338.152232 -231.22509)
		(width 0.088646)
		(layer "In4.Cu")
		(net "M_C_CPU0_SB_DQ<19>")
	)
	(arc
		(start 337.770216 -231.220772)
		(mid 337.490755 -231.149335)
		(end 337.212432 -231.22509)
		(width 0.088646)
		(layer "In4.Cu")
		(net "M_C_CPU0_SB_DQ<19>")
	)
	(arc
		(start 335.332832 -231.224836)
		(mid 335.145634 -231.274979)
		(end 334.958436 -231.224836)
		(width 0.088646)
		(layer "In4.Cu")
		(net "M_C_CPU0_SB_DQ<19>")
	)
	(arc
		(start 334.018636 -231.224836)
		(mid 333.735934 -231.149094)
		(end 333.453232 -231.224836)
		(width 0.088646)
		(layer "In4.Cu")
		(net "M_C_CPU0_SB_DQ<19>")
	)
	(arc
		(start 333.078836 -231.224836)
		(mid 332.796134 -231.149094)
		(end 332.513432 -231.224836)
		(width 0.088646)
		(layer "In4.Cu")
		(net "M_C_CPU0_SB_DQ<19>")
	)
	(arc
		(start 336.83321 -231.222296)
		(mid 336.552546 -231.149288)
		(end 336.272632 -231.22509)
		(width 0.088646)
		(layer "In4.Cu")
		(net "M_C_CPU0_SB_DQ<19>")
	)
	(arc
		(start 339.092032 -231.22509)
		(mid 338.907338 -231.275191)
		(end 338.721954 -231.22763)
		(width 0.088646)
		(layer "In4.Cu")
		(net "M_C_CPU0_SB_DQ<19>")
	)
	(arc
		(start 341.72398 -230.900478)
		(mid 341.539895 -230.8763)
		(end 341.36838 -230.805228)
		(width 0.088646)
		(layer "In4.Cu")
		(net "M_C_CPU0_SB_DQ<19>")
	)
	(arc
		(start 340.59114 -230.579422)
		(mid 340.311035 -230.651864)
		(end 340.031832 -230.57612)
		(width 0.088646)
		(layer "In4.Cu")
		(net "M_C_CPU0_SB_DQ<19>")
	)
	(arc
		(start 339.65134 -230.579422)
		(mid 339.569426 -230.63411)
		(end 339.495384 -230.699056)
		(width 0.088646)
		(layer "In4.Cu")
		(net "M_C_CPU0_SB_DQ<19>")
	)
	(arc
		(start 340.031832 -230.57612)
		(mid 339.847878 -230.525991)
		(end 339.663024 -230.572818)
		(width 0.088646)
		(layer "In4.Cu")
		(net "M_C_CPU0_SB_DQ<19>")
	)
	(arc
		(start 337.212432 -231.22509)
		(mid 337.027738 -231.275191)
		(end 336.842354 -231.22763)
		(width 0.088646)
		(layer "In4.Cu")
		(net "M_C_CPU0_SB_DQ<19>")
	)
	(arc
		(start 336.272632 -231.22509)
		(mid 336.085324 -231.275199)
		(end 335.897982 -231.22509)
		(width 0.088646)
		(layer "In4.Cu")
		(net "M_C_CPU0_SB_DQ<19>")
	)
	(arc
		(start 333.453232 -231.224836)
		(mid 333.266034 -231.274979)
		(end 333.078836 -231.224836)
		(width 0.088646)
		(layer "In4.Cu")
		(net "M_C_CPU0_SB_DQ<19>")
	)
	(arc
		(start 334.958436 -231.224836)
		(mid 334.675734 -231.149094)
		(end 334.393032 -231.224836)
		(width 0.088646)
		(layer "In4.Cu")
		(net "M_C_CPU0_SB_DQ<19>")
	)
	(arc
		(start 339.495384 -230.699056)
		(mid 339.45969 -230.742606)
		(end 339.433154 -230.792274)
		(width 0.088646)
		(layer "In4.Cu")
		(net "M_C_CPU0_SB_DQ<19>")
	)
	(arc
		(start 334.393032 -231.224836)
		(mid 334.205834 -231.274979)
		(end 334.018636 -231.224836)
		(width 0.088646)
		(layer "In4.Cu")
		(net "M_C_CPU0_SB_DQ<19>")
	)
	(arc
		(start 339.367876 -230.950008)
		(mid 339.349992 -230.983309)
		(end 339.325966 -231.012492)
		(width 0.088646)
		(layer "In4.Cu")
		(net "M_C_CPU0_SB_DQ<19>")
	)
	(arc
		(start 332.513432 -231.224836)
		(mid 332.326234 -231.274979)
		(end 332.139036 -231.224836)
		(width 0.088646)
		(layer "In4.Cu")
		(net "M_C_CPU0_SB_DQ<19>")
	)
	(arc
		(start 335.898236 -231.224836)
		(mid 335.615534 -231.149094)
		(end 335.332832 -231.224836)
		(width 0.088646)
		(layer "In4.Cu")
		(net "M_C_CPU0_SB_DQ<19>")
	)
	(arc
		(start 339.184488 -231.15397)
		(mid 339.140601 -231.192575)
		(end 339.092032 -231.22509)
		(width 0.088646)
		(layer "In4.Cu")
		(net "M_C_CPU0_SB_DQ<19>")
	)
	(arc
		(start 338.152232 -231.22509)
		(mid 337.967538 -231.275191)
		(end 337.782154 -231.22763)
		(width 0.088646)
		(layer "In4.Cu")
		(net "M_C_CPU0_SB_DQ<19>")
	)
	(segment
		(start 280.545794 -212.191854)
		(end 279.912826 -212.191854)
		(width 0.20066)
		(layer "F.Cu")
		(net "M_C_CPU0_SB_DQ<18>")
	)
	(segment
		(start 282.811982 -212.616796)
		(end 281.497278 -212.616796)
		(width 0.20066)
		(layer "F.Cu")
		(net "M_C_CPU0_SB_DQ<18>")
	)
	(segment
		(start 280.689558 -212.335618)
		(end 280.545794 -212.191854)
		(width 0.20066)
		(layer "F.Cu")
		(net "M_C_CPU0_SB_DQ<18>")
	)
	(segment
		(start 279.912826 -212.191854)
		(end 277.852886 -212.191854)
		(width 0.1016)
		(layer "F.Cu")
		(net "M_C_CPU0_SB_DQ<18>")
	)
	(segment
		(start 276.850348 -212.181694)
		(end 276.415246 -212.616796)
		(width 0.20066)
		(layer "F.Cu")
		(net "M_C_CPU0_SB_DQ<18>")
	)
	(segment
		(start 341.254334 -232.250488)
		(end 341.25408 -232.250234)
		(width 0.20066)
		(layer "F.Cu")
		(net "M_C_CPU0_SB_DQ<18>")
	)
	(segment
		(start 341.25408 -232.250234)
		(end 341.25408 -231.714548)
		(width 0.20066)
		(layer "F.Cu")
		(net "M_C_CPU0_SB_DQ<18>")
	)
	(segment
		(start 277.852886 -212.191854)
		(end 277.59787 -212.191854)
		(width 0.101854)
		(layer "F.Cu")
		(net "M_C_CPU0_SB_DQ<18>")
	)
	(segment
		(start 280.856944 -212.828632)
		(end 280.689558 -212.661246)
		(width 0.20066)
		(layer "F.Cu")
		(net "M_C_CPU0_SB_DQ<18>")
	)
	(segment
		(start 281.497278 -212.616796)
		(end 281.285442 -212.828632)
		(width 0.20066)
		(layer "F.Cu")
		(net "M_C_CPU0_SB_DQ<18>")
	)
	(segment
		(start 283.916882 -212.616796)
		(end 282.811982 -212.616796)
		(width 0.20066)
		(layer "F.Cu")
		(net "M_C_CPU0_SB_DQ<18>")
	)
	(segment
		(start 276.415246 -212.616796)
		(end 275.268182 -212.616796)
		(width 0.20066)
		(layer "F.Cu")
		(net "M_C_CPU0_SB_DQ<18>")
	)
	(segment
		(start 280.689558 -212.661246)
		(end 280.689558 -212.335618)
		(width 0.20066)
		(layer "F.Cu")
		(net "M_C_CPU0_SB_DQ<18>")
	)
	(segment
		(start 277.58771 -212.181694)
		(end 276.850348 -212.181694)
		(width 0.20066)
		(layer "F.Cu")
		(net "M_C_CPU0_SB_DQ<18>")
	)
	(segment
		(start 277.59787 -212.191854)
		(end 277.58771 -212.181694)
		(width 0.101854)
		(layer "F.Cu")
		(net "M_C_CPU0_SB_DQ<18>")
	)
	(segment
		(start 281.285442 -212.828632)
		(end 280.856944 -212.828632)
		(width 0.20066)
		(layer "F.Cu")
		(net "M_C_CPU0_SB_DQ<18>")
	)
	(segment
		(start 291.890958 -215.591644)
		(end 290.659312 -215.591644)
		(width 0.18288)
		(layer "In4.Cu")
		(net "M_C_CPU0_SB_DQ<18>")
	)
	(segment
		(start 330.905358 -230.98506)
		(end 330.648564 -230.98506)
		(width 0.088646)
		(layer "In4.Cu")
		(net "M_C_CPU0_SB_DQ<18>")
	)
	(segment
		(start 299.701458 -214.74176)
		(end 298.473368 -214.74176)
		(width 0.18288)
		(layer "In4.Cu")
		(net "M_C_CPU0_SB_DQ<18>")
	)
	(segment
		(start 339.567012 -232.036112)
		(end 339.561932 -232.038906)
		(width 0.088646)
		(layer "In4.Cu")
		(net "M_C_CPU0_SB_DQ<18>")
	)
	(segment
		(start 290.160456 -215.092788)
		(end 290.160456 -214.834216)
		(width 0.18288)
		(layer "In4.Cu")
		(net "M_C_CPU0_SB_DQ<18>")
	)
	(segment
		(start 300.947836 -214.884)
		(end 300.764956 -215.06688)
		(width 0.18288)
		(layer "In4.Cu")
		(net "M_C_CPU0_SB_DQ<18>")
	)
	(segment
		(start 305.125882 -215.21166)
		(end 304.943002 -215.02878)
		(width 0.18288)
		(layer "In4.Cu")
		(net "M_C_CPU0_SB_DQ<18>")
	)
	(segment
		(start 338.627974 -232.03535)
		(end 338.622132 -232.038906)
		(width 0.088646)
		(layer "In4.Cu")
		(net "M_C_CPU0_SB_DQ<18>")
	)
	(segment
		(start 305.451002 -215.21166)
		(end 305.125882 -215.21166)
		(width 0.18288)
		(layer "In4.Cu")
		(net "M_C_CPU0_SB_DQ<18>")
	)
	(segment
		(start 292.20287 -215.279732)
		(end 291.890958 -215.591644)
		(width 0.18288)
		(layer "In4.Cu")
		(net "M_C_CPU0_SB_DQ<18>")
	)
	(segment
		(start 297.623484 -215.591644)
		(end 294.27551 -215.591644)
		(width 0.18288)
		(layer "In4.Cu")
		(net "M_C_CPU0_SB_DQ<18>")
	)
	(segment
		(start 306.666392 -214.50808)
		(end 305.816762 -214.50808)
		(width 0.18288)
		(layer "In4.Cu")
		(net "M_C_CPU0_SB_DQ<18>")
	)
	(segment
		(start 312.858912 -215.771984)
		(end 312.72226 -215.908636)
		(width 0.18288)
		(layer "In4.Cu")
		(net "M_C_CPU0_SB_DQ<18>")
	)
	(segment
		(start 332.998064 -232.03027)
		(end 332.983332 -232.038906)
		(width 0.088646)
		(layer "In4.Cu")
		(net "M_C_CPU0_SB_DQ<18>")
	)
	(segment
		(start 293.272718 -215.591644)
		(end 292.89375 -215.591644)
		(width 0.18288)
		(layer "In4.Cu")
		(net "M_C_CPU0_SB_DQ<18>")
	)
	(segment
		(start 340.269576 -231.26827)
		(end 340.131908 -231.26827)
		(width 0.088646)
		(layer "In4.Cu")
		(net "M_C_CPU0_SB_DQ<18>")
	)
	(segment
		(start 315.300106 -218.745054)
		(end 313.210956 -216.655904)
		(width 0.18288)
		(layer "In4.Cu")
		(net "M_C_CPU0_SB_DQ<18>")
	)
	(segment
		(start 284.54477 -213.244684)
		(end 283.916882 -212.616796)
		(width 0.18288)
		(layer "In4.Cu")
		(net "M_C_CPU0_SB_DQ<18>")
	)
	(segment
		(start 289.413188 -214.34552)
		(end 288.91992 -213.852252)
		(width 0.18288)
		(layer "In4.Cu")
		(net "M_C_CPU0_SB_DQ<18>")
	)
	(segment
		(start 313.210956 -216.397332)
		(end 313.347608 -216.26068)
		(width 0.18288)
		(layer "In4.Cu")
		(net "M_C_CPU0_SB_DQ<18>")
	)
	(segment
		(start 313.210956 -216.655904)
		(end 313.210956 -216.397332)
		(width 0.18288)
		(layer "In4.Cu")
		(net "M_C_CPU0_SB_DQ<18>")
	)
	(segment
		(start 304.943002 -215.02878)
		(end 304.943002 -214.69096)
		(width 0.18288)
		(layer "In4.Cu")
		(net "M_C_CPU0_SB_DQ<18>")
	)
	(segment
		(start 300.026578 -215.06688)
		(end 299.701458 -214.74176)
		(width 0.18288)
		(layer "In4.Cu")
		(net "M_C_CPU0_SB_DQ<18>")
	)
	(segment
		(start 308.779672 -214.31123)
		(end 308.596792 -214.49411)
		(width 0.18288)
		(layer "In4.Cu")
		(net "M_C_CPU0_SB_DQ<18>")
	)
	(segment
		(start 305.816762 -214.50808)
		(end 305.633882 -214.69096)
		(width 0.18288)
		(layer "In4.Cu")
		(net "M_C_CPU0_SB_DQ<18>")
	)
	(segment
		(start 303.28362 -214.50808)
		(end 302.72482 -215.06688)
		(width 0.18288)
		(layer "In4.Cu")
		(net "M_C_CPU0_SB_DQ<18>")
	)
	(segment
		(start 302.72482 -215.06688)
		(end 301.821596 -215.06688)
		(width 0.18288)
		(layer "In4.Cu")
		(net "M_C_CPU0_SB_DQ<18>")
	)
	(segment
		(start 309.470552 -214.874602)
		(end 309.287672 -214.691722)
		(width 0.18288)
		(layer "In4.Cu")
		(net "M_C_CPU0_SB_DQ<18>")
	)
	(segment
		(start 338.622132 -232.038906)
		(end 338.61629 -232.042208)
		(width 0.088646)
		(layer "In4.Cu")
		(net "M_C_CPU0_SB_DQ<18>")
	)
	(segment
		(start 307.032914 -214.874602)
		(end 306.666392 -214.50808)
		(width 0.18288)
		(layer "In4.Cu")
		(net "M_C_CPU0_SB_DQ<18>")
	)
	(segment
		(start 286.129984 -213.244684)
		(end 284.54477 -213.244684)
		(width 0.18288)
		(layer "In4.Cu")
		(net "M_C_CPU0_SB_DQ<18>")
	)
	(segment
		(start 310.460898 -214.874602)
		(end 309.470552 -214.874602)
		(width 0.18288)
		(layer "In4.Cu")
		(net "M_C_CPU0_SB_DQ<18>")
	)
	(segment
		(start 301.130716 -214.307166)
		(end 300.947836 -214.490046)
		(width 0.18288)
		(layer "In4.Cu")
		(net "M_C_CPU0_SB_DQ<18>")
	)
	(segment
		(start 312.72226 -215.908636)
		(end 312.463688 -215.908636)
		(width 0.18288)
		(layer "In4.Cu")
		(net "M_C_CPU0_SB_DQ<18>")
	)
	(segment
		(start 290.455858 -213.819994)
		(end 290.197286 -213.819994)
		(width 0.18288)
		(layer "In4.Cu")
		(net "M_C_CPU0_SB_DQ<18>")
	)
	(segment
		(start 293.963598 -215.279732)
		(end 293.58463 -215.279732)
		(width 0.18288)
		(layer "In4.Cu")
		(net "M_C_CPU0_SB_DQ<18>")
	)
	(segment
		(start 294.27551 -215.591644)
		(end 293.963598 -215.279732)
		(width 0.18288)
		(layer "In4.Cu")
		(net "M_C_CPU0_SB_DQ<18>")
	)
	(segment
		(start 293.58463 -215.279732)
		(end 293.272718 -215.591644)
		(width 0.18288)
		(layer "In4.Cu")
		(net "M_C_CPU0_SB_DQ<18>")
	)
	(segment
		(start 290.659312 -215.591644)
		(end 290.160456 -215.092788)
		(width 0.18288)
		(layer "In4.Cu")
		(net "M_C_CPU0_SB_DQ<18>")
	)
	(segment
		(start 305.633882 -215.02878)
		(end 305.451002 -215.21166)
		(width 0.18288)
		(layer "In4.Cu")
		(net "M_C_CPU0_SB_DQ<18>")
	)
	(segment
		(start 308.596792 -214.691722)
		(end 308.413912 -214.874602)
		(width 0.18288)
		(layer "In4.Cu")
		(net "M_C_CPU0_SB_DQ<18>")
	)
	(segment
		(start 301.638716 -214.884)
		(end 301.638716 -214.490046)
		(width 0.18288)
		(layer "In4.Cu")
		(net "M_C_CPU0_SB_DQ<18>")
	)
	(segment
		(start 341.25408 -231.714294)
		(end 341.188802 -231.649016)
		(width 0.088646)
		(layer "In4.Cu")
		(net "M_C_CPU0_SB_DQ<18>")
	)
	(segment
		(start 337.682332 -232.038906)
		(end 337.67649 -232.042208)
		(width 0.088646)
		(layer "In4.Cu")
		(net "M_C_CPU0_SB_DQ<18>")
	)
	(segment
		(start 304.760122 -214.50808)
		(end 303.28362 -214.50808)
		(width 0.18288)
		(layer "In4.Cu")
		(net "M_C_CPU0_SB_DQ<18>")
	)
	(segment
		(start 305.633882 -214.69096)
		(end 305.633882 -215.02878)
		(width 0.18288)
		(layer "In4.Cu")
		(net "M_C_CPU0_SB_DQ<18>")
	)
	(segment
		(start 336.742532 -232.038906)
		(end 336.738722 -232.040938)
		(width 0.088646)
		(layer "In4.Cu")
		(net "M_C_CPU0_SB_DQ<18>")
	)
	(segment
		(start 308.596792 -214.49411)
		(end 308.596792 -214.691722)
		(width 0.18288)
		(layer "In4.Cu")
		(net "M_C_CPU0_SB_DQ<18>")
	)
	(segment
		(start 292.89375 -215.591644)
		(end 292.581838 -215.279732)
		(width 0.18288)
		(layer "In4.Cu")
		(net "M_C_CPU0_SB_DQ<18>")
	)
	(segment
		(start 330.648564 -230.98506)
		(end 324.859142 -230.98506)
		(width 0.18288)
		(layer "In4.Cu")
		(net "M_C_CPU0_SB_DQ<18>")
	)
	(segment
		(start 309.287672 -214.49411)
		(end 309.104792 -214.31123)
		(width 0.18288)
		(layer "In4.Cu")
		(net "M_C_CPU0_SB_DQ<18>")
	)
	(segment
		(start 300.764956 -215.06688)
		(end 300.026578 -215.06688)
		(width 0.18288)
		(layer "In4.Cu")
		(net "M_C_CPU0_SB_DQ<18>")
	)
	(segment
		(start 290.197286 -213.819994)
		(end 289.67176 -214.34552)
		(width 0.18288)
		(layer "In4.Cu")
		(net "M_C_CPU0_SB_DQ<18>")
	)
	(segment
		(start 288.91992 -213.852252)
		(end 286.737552 -213.852252)
		(width 0.18288)
		(layer "In4.Cu")
		(net "M_C_CPU0_SB_DQ<18>")
	)
	(segment
		(start 290.685982 -214.30869)
		(end 290.685982 -214.050118)
		(width 0.18288)
		(layer "In4.Cu")
		(net "M_C_CPU0_SB_DQ<18>")
	)
	(segment
		(start 286.737552 -213.852252)
		(end 286.129984 -213.244684)
		(width 0.18288)
		(layer "In4.Cu")
		(net "M_C_CPU0_SB_DQ<18>")
	)
	(segment
		(start 301.455836 -214.307166)
		(end 301.130716 -214.307166)
		(width 0.18288)
		(layer "In4.Cu")
		(net "M_C_CPU0_SB_DQ<18>")
	)
	(segment
		(start 339.561932 -232.038906)
		(end 339.55609 -232.042208)
		(width 0.088646)
		(layer "In4.Cu")
		(net "M_C_CPU0_SB_DQ<18>")
	)
	(segment
		(start 339.749384 -231.70642)
		(end 339.749384 -231.714548)
		(width 0.088646)
		(layer "In4.Cu")
		(net "M_C_CPU0_SB_DQ<18>")
	)
	(segment
		(start 336.748374 -232.03535)
		(end 336.742532 -232.038906)
		(width 0.088646)
		(layer "In4.Cu")
		(net "M_C_CPU0_SB_DQ<18>")
	)
	(segment
		(start 332.058264 -232.03027)
		(end 331.950568 -232.03027)
		(width 0.088646)
		(layer "In4.Cu")
		(net "M_C_CPU0_SB_DQ<18>")
	)
	(segment
		(start 308.413912 -214.874602)
		(end 307.032914 -214.874602)
		(width 0.18288)
		(layer "In4.Cu")
		(net "M_C_CPU0_SB_DQ<18>")
	)
	(segment
		(start 300.947836 -214.490046)
		(end 300.947836 -214.884)
		(width 0.18288)
		(layer "In4.Cu")
		(net "M_C_CPU0_SB_DQ<18>")
	)
	(segment
		(start 331.950568 -232.03027)
		(end 330.905358 -230.98506)
		(width 0.088646)
		(layer "In4.Cu")
		(net "M_C_CPU0_SB_DQ<18>")
	)
	(segment
		(start 304.943002 -214.69096)
		(end 304.760122 -214.50808)
		(width 0.18288)
		(layer "In4.Cu")
		(net "M_C_CPU0_SB_DQ<18>")
	)
	(segment
		(start 312.463688 -215.908636)
		(end 312.24093 -215.685878)
		(width 0.18288)
		(layer "In4.Cu")
		(net "M_C_CPU0_SB_DQ<18>")
	)
	(segment
		(start 317.195962 -223.32188)
		(end 315.300106 -218.745054)
		(width 0.18288)
		(layer "In4.Cu")
		(net "M_C_CPU0_SB_DQ<18>")
	)
	(segment
		(start 298.473368 -214.74176)
		(end 297.623484 -215.591644)
		(width 0.18288)
		(layer "In4.Cu")
		(net "M_C_CPU0_SB_DQ<18>")
	)
	(segment
		(start 301.638716 -214.490046)
		(end 301.455836 -214.307166)
		(width 0.18288)
		(layer "In4.Cu")
		(net "M_C_CPU0_SB_DQ<18>")
	)
	(segment
		(start 289.67176 -214.34552)
		(end 289.413188 -214.34552)
		(width 0.18288)
		(layer "In4.Cu")
		(net "M_C_CPU0_SB_DQ<18>")
	)
	(segment
		(start 341.25408 -231.714548)
		(end 341.25408 -231.714294)
		(width 0.088646)
		(layer "In4.Cu")
		(net "M_C_CPU0_SB_DQ<18>")
	)
	(segment
		(start 313.347608 -216.002108)
		(end 313.117484 -215.771984)
		(width 0.18288)
		(layer "In4.Cu")
		(net "M_C_CPU0_SB_DQ<18>")
	)
	(segment
		(start 309.104792 -214.31123)
		(end 308.779672 -214.31123)
		(width 0.18288)
		(layer "In4.Cu")
		(net "M_C_CPU0_SB_DQ<18>")
	)
	(segment
		(start 290.160456 -214.834216)
		(end 290.685982 -214.30869)
		(width 0.18288)
		(layer "In4.Cu")
		(net "M_C_CPU0_SB_DQ<18>")
	)
	(segment
		(start 311.272174 -215.685878)
		(end 310.460898 -214.874602)
		(width 0.18288)
		(layer "In4.Cu")
		(net "M_C_CPU0_SB_DQ<18>")
	)
	(segment
		(start 312.24093 -215.685878)
		(end 311.272174 -215.685878)
		(width 0.18288)
		(layer "In4.Cu")
		(net "M_C_CPU0_SB_DQ<18>")
	)
	(segment
		(start 292.581838 -215.279732)
		(end 292.20287 -215.279732)
		(width 0.18288)
		(layer "In4.Cu")
		(net "M_C_CPU0_SB_DQ<18>")
	)
	(segment
		(start 324.859142 -230.98506)
		(end 317.195962 -223.32188)
		(width 0.18288)
		(layer "In4.Cu")
		(net "M_C_CPU0_SB_DQ<18>")
	)
	(segment
		(start 313.347608 -216.26068)
		(end 313.347608 -216.002108)
		(width 0.18288)
		(layer "In4.Cu")
		(net "M_C_CPU0_SB_DQ<18>")
	)
	(segment
		(start 309.287672 -214.691722)
		(end 309.287672 -214.49411)
		(width 0.18288)
		(layer "In4.Cu")
		(net "M_C_CPU0_SB_DQ<18>")
	)
	(segment
		(start 337.688174 -232.03535)
		(end 337.682332 -232.038906)
		(width 0.088646)
		(layer "In4.Cu")
		(net "M_C_CPU0_SB_DQ<18>")
	)
	(segment
		(start 290.685982 -214.050118)
		(end 290.455858 -213.819994)
		(width 0.18288)
		(layer "In4.Cu")
		(net "M_C_CPU0_SB_DQ<18>")
	)
	(segment
		(start 313.117484 -215.771984)
		(end 312.858912 -215.771984)
		(width 0.18288)
		(layer "In4.Cu")
		(net "M_C_CPU0_SB_DQ<18>")
	)
	(segment
		(start 301.821596 -215.06688)
		(end 301.638716 -214.884)
		(width 0.18288)
		(layer "In4.Cu")
		(net "M_C_CPU0_SB_DQ<18>")
	)
	(arc
		(start 338.61629 -232.042208)
		(mid 338.431435 -232.089158)
		(end 338.247482 -232.038906)
		(width 0.088646)
		(layer "In4.Cu")
		(net "M_C_CPU0_SB_DQ<18>")
	)
	(arc
		(start 333.923132 -232.038906)
		(mid 333.735934 -232.089049)
		(end 333.548736 -232.038906)
		(width 0.088646)
		(layer "In4.Cu")
		(net "M_C_CPU0_SB_DQ<18>")
	)
	(arc
		(start 339.749384 -231.714548)
		(mid 339.700636 -231.899414)
		(end 339.567012 -232.036112)
		(width 0.088646)
		(layer "In4.Cu")
		(net "M_C_CPU0_SB_DQ<18>")
	)
	(arc
		(start 334.862932 -232.038906)
		(mid 334.675734 -232.089049)
		(end 334.488536 -232.038906)
		(width 0.088646)
		(layer "In4.Cu")
		(net "M_C_CPU0_SB_DQ<18>")
	)
	(arc
		(start 334.488536 -232.038906)
		(mid 334.205834 -231.96313)
		(end 333.923132 -232.038906)
		(width 0.088646)
		(layer "In4.Cu")
		(net "M_C_CPU0_SB_DQ<18>")
	)
	(arc
		(start 335.428336 -232.038906)
		(mid 335.145634 -231.96313)
		(end 334.862932 -232.038906)
		(width 0.088646)
		(layer "In4.Cu")
		(net "M_C_CPU0_SB_DQ<18>")
	)
	(arc
		(start 335.802732 -232.038906)
		(mid 335.615534 -232.089049)
		(end 335.428336 -232.038906)
		(width 0.088646)
		(layer "In4.Cu")
		(net "M_C_CPU0_SB_DQ<18>")
	)
	(arc
		(start 338.247482 -232.038906)
		(mid 337.968308 -231.963141)
		(end 337.688174 -232.03535)
		(width 0.088646)
		(layer "In4.Cu")
		(net "M_C_CPU0_SB_DQ<18>")
	)
	(arc
		(start 333.548736 -232.038906)
		(mid 333.274537 -231.963071)
		(end 332.998064 -232.03027)
		(width 0.088646)
		(layer "In4.Cu")
		(net "M_C_CPU0_SB_DQ<18>")
	)
	(arc
		(start 337.67649 -232.042208)
		(mid 337.491635 -232.089158)
		(end 337.307682 -232.038906)
		(width 0.088646)
		(layer "In4.Cu")
		(net "M_C_CPU0_SB_DQ<18>")
	)
	(arc
		(start 332.608936 -232.038906)
		(mid 332.334737 -231.963071)
		(end 332.058264 -232.03027)
		(width 0.088646)
		(layer "In4.Cu")
		(net "M_C_CPU0_SB_DQ<18>")
	)
	(arc
		(start 337.307682 -232.038906)
		(mid 337.028508 -231.963141)
		(end 336.748374 -232.03535)
		(width 0.088646)
		(layer "In4.Cu")
		(net "M_C_CPU0_SB_DQ<18>")
	)
	(arc
		(start 340.131908 -231.26827)
		(mid 339.932039 -231.327709)
		(end 339.797136 -231.48671)
		(width 0.088646)
		(layer "In4.Cu")
		(net "M_C_CPU0_SB_DQ<18>")
	)
	(arc
		(start 336.738722 -232.040938)
		(mid 336.553032 -232.089048)
		(end 336.367882 -232.038906)
		(width 0.088646)
		(layer "In4.Cu")
		(net "M_C_CPU0_SB_DQ<18>")
	)
	(arc
		(start 341.188802 -231.649016)
		(mid 340.767058 -231.367215)
		(end 340.269576 -231.26827)
		(width 0.088646)
		(layer "In4.Cu")
		(net "M_C_CPU0_SB_DQ<18>")
	)
	(arc
		(start 339.55609 -232.042208)
		(mid 339.371235 -232.089158)
		(end 339.187282 -232.038906)
		(width 0.088646)
		(layer "In4.Cu")
		(net "M_C_CPU0_SB_DQ<18>")
	)
	(arc
		(start 339.797136 -231.48671)
		(mid 339.762208 -231.594165)
		(end 339.749384 -231.70642)
		(width 0.088646)
		(layer "In4.Cu")
		(net "M_C_CPU0_SB_DQ<18>")
	)
	(arc
		(start 339.187282 -232.038906)
		(mid 338.908108 -231.963141)
		(end 338.627974 -232.03535)
		(width 0.088646)
		(layer "In4.Cu")
		(net "M_C_CPU0_SB_DQ<18>")
	)
	(arc
		(start 336.367882 -232.038906)
		(mid 336.085324 -231.963257)
		(end 335.802732 -232.038906)
		(width 0.088646)
		(layer "In4.Cu")
		(net "M_C_CPU0_SB_DQ<18>")
	)
	(arc
		(start 332.983332 -232.038906)
		(mid 332.796134 -232.089049)
		(end 332.608936 -232.038906)
		(width 0.088646)
		(layer "In4.Cu")
		(net "M_C_CPU0_SB_DQ<18>")
	)
	(segment
		(start 273.37258 -211.823554)
		(end 273.218148 -211.977986)
		(width 0.20066)
		(layer "F.Cu")
		(net "M_C_CPU0_SB_DQ<17>")
	)
	(segment
		(start 279.816814 -211.766658)
		(end 278.711914 -211.766658)
		(width 0.20066)
		(layer "F.Cu")
		(net "M_C_CPU0_SB_DQ<17>")
	)
	(segment
		(start 276.138386 -211.341716)
		(end 274.152868 -211.341716)
		(width 0.1016)
		(layer "F.Cu")
		(net "M_C_CPU0_SB_DQ<17>")
	)
	(segment
		(start 339.84438 -231.436418)
		(end 339.844634 -231.436164)
		(width 0.20066)
		(layer "F.Cu")
		(net "M_C_CPU0_SB_DQ<17>")
	)
	(segment
		(start 276.469094 -211.341716)
		(end 276.138386 -211.341716)
		(width 0.101854)
		(layer "F.Cu")
		(net "M_C_CPU0_SB_DQ<17>")
	)
	(segment
		(start 272.502376 -211.766658)
		(end 271.168114 -211.766658)
		(width 0.20066)
		(layer "F.Cu")
		(net "M_C_CPU0_SB_DQ<17>")
	)
	(segment
		(start 277.072598 -211.766658)
		(end 276.647656 -211.341716)
		(width 0.20066)
		(layer "F.Cu")
		(net "M_C_CPU0_SB_DQ<17>")
	)
	(segment
		(start 274.143978 -211.332826)
		(end 273.53514 -211.332826)
		(width 0.20066)
		(layer "F.Cu")
		(net "M_C_CPU0_SB_DQ<17>")
	)
	(segment
		(start 339.844634 -231.436164)
		(end 339.844634 -230.900478)
		(width 0.20066)
		(layer "F.Cu")
		(net "M_C_CPU0_SB_DQ<17>")
	)
	(segment
		(start 273.218148 -211.977986)
		(end 272.713704 -211.977986)
		(width 0.20066)
		(layer "F.Cu")
		(net "M_C_CPU0_SB_DQ<17>")
	)
	(segment
		(start 276.647656 -211.341716)
		(end 276.469094 -211.341716)
		(width 0.20066)
		(layer "F.Cu")
		(net "M_C_CPU0_SB_DQ<17>")
	)
	(segment
		(start 274.152868 -211.341716)
		(end 274.143978 -211.332826)
		(width 0.1016)
		(layer "F.Cu")
		(net "M_C_CPU0_SB_DQ<17>")
	)
	(segment
		(start 273.37258 -211.495386)
		(end 273.37258 -211.823554)
		(width 0.20066)
		(layer "F.Cu")
		(net "M_C_CPU0_SB_DQ<17>")
	)
	(segment
		(start 278.711914 -211.766658)
		(end 277.072598 -211.766658)
		(width 0.20066)
		(layer "F.Cu")
		(net "M_C_CPU0_SB_DQ<17>")
	)
	(segment
		(start 273.53514 -211.332826)
		(end 273.37258 -211.495386)
		(width 0.20066)
		(layer "F.Cu")
		(net "M_C_CPU0_SB_DQ<17>")
	)
	(segment
		(start 272.713704 -211.977986)
		(end 272.502376 -211.766658)
		(width 0.20066)
		(layer "F.Cu")
		(net "M_C_CPU0_SB_DQ<17>")
	)
	(segment
		(start 297.710606 -214.74176)
		(end 292.082728 -214.74176)
		(width 0.18288)
		(layer "In4.Cu")
		(net "M_C_CPU0_SB_DQ<17>")
	)
	(segment
		(start 337.682332 -231.389936)
		(end 337.67776 -231.387396)
		(width 0.088646)
		(layer "In4.Cu")
		(net "M_C_CPU0_SB_DQ<17>")
	)
	(segment
		(start 299.701458 -213.891876)
		(end 298.56049 -213.891876)
		(width 0.18288)
		(layer "In4.Cu")
		(net "M_C_CPU0_SB_DQ<17>")
	)
	(segment
		(start 317.600584 -222.997268)
		(end 315.11494 -216.996772)
		(width 0.18288)
		(layer "In4.Cu")
		(net "M_C_CPU0_SB_DQ<17>")
	)
	(segment
		(start 325.08317 -230.479854)
		(end 317.600584 -222.997268)
		(width 0.18288)
		(layer "In4.Cu")
		(net "M_C_CPU0_SB_DQ<17>")
	)
	(segment
		(start 280.42489 -212.374734)
		(end 279.816814 -211.766658)
		(width 0.18288)
		(layer "In4.Cu")
		(net "M_C_CPU0_SB_DQ<17>")
	)
	(segment
		(start 290.273486 -212.932518)
		(end 288.072576 -212.932518)
		(width 0.18288)
		(layer "In4.Cu")
		(net "M_C_CPU0_SB_DQ<17>")
	)
	(segment
		(start 281.29865 -212.191854)
		(end 281.11577 -212.374734)
		(width 0.18288)
		(layer "In4.Cu")
		(net "M_C_CPU0_SB_DQ<17>")
	)
	(segment
		(start 280.60777 -213.187788)
		(end 280.42489 -213.004908)
		(width 0.18288)
		(layer "In4.Cu")
		(net "M_C_CPU0_SB_DQ<17>")
	)
	(segment
		(start 282.294076 -213.16315)
		(end 282.294076 -212.374734)
		(width 0.18288)
		(layer "In4.Cu")
		(net "M_C_CPU0_SB_DQ<17>")
	)
	(segment
		(start 336.742532 -231.389936)
		(end 336.738722 -231.387904)
		(width 0.088646)
		(layer "In4.Cu")
		(net "M_C_CPU0_SB_DQ<17>")
	)
	(segment
		(start 280.93289 -213.187788)
		(end 280.60777 -213.187788)
		(width 0.18288)
		(layer "In4.Cu")
		(net "M_C_CPU0_SB_DQ<17>")
	)
	(segment
		(start 292.082728 -214.74176)
		(end 290.273486 -212.932518)
		(width 0.18288)
		(layer "In4.Cu")
		(net "M_C_CPU0_SB_DQ<17>")
	)
	(segment
		(start 315.11494 -216.996772)
		(end 312.742834 -214.624666)
		(width 0.18288)
		(layer "In4.Cu")
		(net "M_C_CPU0_SB_DQ<17>")
	)
	(segment
		(start 282.111196 -212.191854)
		(end 281.29865 -212.191854)
		(width 0.18288)
		(layer "In4.Cu")
		(net "M_C_CPU0_SB_DQ<17>")
	)
	(segment
		(start 280.42489 -213.004908)
		(end 280.42489 -212.374734)
		(width 0.18288)
		(layer "In4.Cu")
		(net "M_C_CPU0_SB_DQ<17>")
	)
	(segment
		(start 337.689698 -231.394254)
		(end 337.682332 -231.389936)
		(width 0.088646)
		(layer "In4.Cu")
		(net "M_C_CPU0_SB_DQ<17>")
	)
	(segment
		(start 336.749898 -231.394254)
		(end 336.742532 -231.389936)
		(width 0.088646)
		(layer "In4.Cu")
		(net "M_C_CPU0_SB_DQ<17>")
	)
	(segment
		(start 310.68645 -213.81339)
		(end 306.880514 -213.81339)
		(width 0.18288)
		(layer "In4.Cu")
		(net "M_C_CPU0_SB_DQ<17>")
	)
	(segment
		(start 335.802732 -231.389936)
		(end 335.802732 -231.39019)
		(width 0.088646)
		(layer "In4.Cu")
		(net "M_C_CPU0_SB_DQ<17>")
	)
	(segment
		(start 338.622132 -231.389936)
		(end 338.61756 -231.387396)
		(width 0.088646)
		(layer "In4.Cu")
		(net "M_C_CPU0_SB_DQ<17>")
	)
	(segment
		(start 299.815504 -213.77783)
		(end 299.701458 -213.891876)
		(width 0.18288)
		(layer "In4.Cu")
		(net "M_C_CPU0_SB_DQ<17>")
	)
	(segment
		(start 281.11577 -212.374734)
		(end 281.11577 -213.004908)
		(width 0.18288)
		(layer "In4.Cu")
		(net "M_C_CPU0_SB_DQ<17>")
	)
	(segment
		(start 312.742834 -214.624666)
		(end 311.497726 -214.624666)
		(width 0.18288)
		(layer "In4.Cu")
		(net "M_C_CPU0_SB_DQ<17>")
	)
	(segment
		(start 338.629498 -231.394254)
		(end 338.622132 -231.389936)
		(width 0.088646)
		(layer "In4.Cu")
		(net "M_C_CPU0_SB_DQ<17>")
	)
	(segment
		(start 339.260688 -231.347772)
		(end 339.187282 -231.389936)
		(width 0.088646)
		(layer "In4.Cu")
		(net "M_C_CPU0_SB_DQ<17>")
	)
	(segment
		(start 298.56049 -213.891876)
		(end 297.710606 -214.74176)
		(width 0.18288)
		(layer "In4.Cu")
		(net "M_C_CPU0_SB_DQ<17>")
	)
	(segment
		(start 330.648564 -230.479854)
		(end 325.08317 -230.479854)
		(width 0.18288)
		(layer "In4.Cu")
		(net "M_C_CPU0_SB_DQ<17>")
	)
	(segment
		(start 288.072576 -212.932518)
		(end 287.82264 -213.182454)
		(width 0.18288)
		(layer "In4.Cu")
		(net "M_C_CPU0_SB_DQ<17>")
	)
	(segment
		(start 287.82264 -213.182454)
		(end 287.090866 -213.182454)
		(width 0.18288)
		(layer "In4.Cu")
		(net "M_C_CPU0_SB_DQ<17>")
	)
	(segment
		(start 303.461928 -213.982554)
		(end 303.257204 -213.77783)
		(width 0.18288)
		(layer "In4.Cu")
		(net "M_C_CPU0_SB_DQ<17>")
	)
	(segment
		(start 306.880514 -213.81339)
		(end 306.71135 -213.982554)
		(width 0.18288)
		(layer "In4.Cu")
		(net "M_C_CPU0_SB_DQ<17>")
	)
	(segment
		(start 306.71135 -213.982554)
		(end 303.461928 -213.982554)
		(width 0.18288)
		(layer "In4.Cu")
		(net "M_C_CPU0_SB_DQ<17>")
	)
	(segment
		(start 283.167836 -212.191854)
		(end 282.984956 -212.374734)
		(width 0.18288)
		(layer "In4.Cu")
		(net "M_C_CPU0_SB_DQ<17>")
	)
	(segment
		(start 282.984956 -212.374734)
		(end 282.984956 -213.16315)
		(width 0.18288)
		(layer "In4.Cu")
		(net "M_C_CPU0_SB_DQ<17>")
	)
	(segment
		(start 282.476956 -213.34603)
		(end 282.294076 -213.16315)
		(width 0.18288)
		(layer "In4.Cu")
		(net "M_C_CPU0_SB_DQ<17>")
	)
	(segment
		(start 311.497726 -214.624666)
		(end 310.68645 -213.81339)
		(width 0.18288)
		(layer "In4.Cu")
		(net "M_C_CPU0_SB_DQ<17>")
	)
	(segment
		(start 282.984956 -213.16315)
		(end 282.802076 -213.34603)
		(width 0.18288)
		(layer "In4.Cu")
		(net "M_C_CPU0_SB_DQ<17>")
	)
	(segment
		(start 331.918056 -231.299258)
		(end 331.098652 -230.479854)
		(width 0.088646)
		(layer "In4.Cu")
		(net "M_C_CPU0_SB_DQ<17>")
	)
	(segment
		(start 287.090866 -213.182454)
		(end 286.100266 -212.191854)
		(width 0.18288)
		(layer "In4.Cu")
		(net "M_C_CPU0_SB_DQ<17>")
	)
	(segment
		(start 286.100266 -212.191854)
		(end 283.167836 -212.191854)
		(width 0.18288)
		(layer "In4.Cu")
		(net "M_C_CPU0_SB_DQ<17>")
	)
	(segment
		(start 303.257204 -213.77783)
		(end 299.815504 -213.77783)
		(width 0.18288)
		(layer "In4.Cu")
		(net "M_C_CPU0_SB_DQ<17>")
	)
	(segment
		(start 281.11577 -213.004908)
		(end 280.93289 -213.187788)
		(width 0.18288)
		(layer "In4.Cu")
		(net "M_C_CPU0_SB_DQ<17>")
	)
	(segment
		(start 282.294076 -212.374734)
		(end 282.111196 -212.191854)
		(width 0.18288)
		(layer "In4.Cu")
		(net "M_C_CPU0_SB_DQ<17>")
	)
	(segment
		(start 282.802076 -213.34603)
		(end 282.476956 -213.34603)
		(width 0.18288)
		(layer "In4.Cu")
		(net "M_C_CPU0_SB_DQ<17>")
	)
	(segment
		(start 331.098652 -230.479854)
		(end 330.648564 -230.479854)
		(width 0.088646)
		(layer "In4.Cu")
		(net "M_C_CPU0_SB_DQ<17>")
	)
	(arc
		(start 333.923132 -231.39019)
		(mid 333.735934 -231.340047)
		(end 333.548736 -231.39019)
		(width 0.088646)
		(layer "In4.Cu")
		(net "M_C_CPU0_SB_DQ<17>")
	)
	(arc
		(start 334.488536 -231.39019)
		(mid 334.205834 -231.465932)
		(end 333.923132 -231.39019)
		(width 0.088646)
		(layer "In4.Cu")
		(net "M_C_CPU0_SB_DQ<17>")
	)
	(arc
		(start 334.862932 -231.39019)
		(mid 334.675734 -231.340047)
		(end 334.488536 -231.39019)
		(width 0.088646)
		(layer "In4.Cu")
		(net "M_C_CPU0_SB_DQ<17>")
	)
	(arc
		(start 335.428336 -231.39019)
		(mid 335.145634 -231.465932)
		(end 334.862932 -231.39019)
		(width 0.088646)
		(layer "In4.Cu")
		(net "M_C_CPU0_SB_DQ<17>")
	)
	(arc
		(start 333.548736 -231.39019)
		(mid 333.266034 -231.465932)
		(end 332.983332 -231.39019)
		(width 0.088646)
		(layer "In4.Cu")
		(net "M_C_CPU0_SB_DQ<17>")
	)
	(arc
		(start 339.844634 -230.900478)
		(mid 339.567454 -231.143439)
		(end 339.260688 -231.347772)
		(width 0.088646)
		(layer "In4.Cu")
		(net "M_C_CPU0_SB_DQ<17>")
	)
	(arc
		(start 339.187282 -231.389936)
		(mid 338.908959 -231.465695)
		(end 338.629498 -231.394254)
		(width 0.088646)
		(layer "In4.Cu")
		(net "M_C_CPU0_SB_DQ<17>")
	)
	(arc
		(start 332.608936 -231.39019)
		(mid 332.248041 -231.462007)
		(end 331.918056 -231.299258)
		(width 0.088646)
		(layer "In4.Cu")
		(net "M_C_CPU0_SB_DQ<17>")
	)
	(arc
		(start 337.67776 -231.387396)
		(mid 337.492375 -231.339758)
		(end 337.307682 -231.389936)
		(width 0.088646)
		(layer "In4.Cu")
		(net "M_C_CPU0_SB_DQ<17>")
	)
	(arc
		(start 338.61756 -231.387396)
		(mid 338.432175 -231.339758)
		(end 338.247482 -231.389936)
		(width 0.088646)
		(layer "In4.Cu")
		(net "M_C_CPU0_SB_DQ<17>")
	)
	(arc
		(start 336.738722 -231.387904)
		(mid 336.553032 -231.339826)
		(end 336.367882 -231.389936)
		(width 0.088646)
		(layer "In4.Cu")
		(net "M_C_CPU0_SB_DQ<17>")
	)
	(arc
		(start 338.247482 -231.389936)
		(mid 337.969159 -231.465695)
		(end 337.689698 -231.394254)
		(width 0.088646)
		(layer "In4.Cu")
		(net "M_C_CPU0_SB_DQ<17>")
	)
	(arc
		(start 335.802732 -231.39019)
		(mid 335.615534 -231.340047)
		(end 335.428336 -231.39019)
		(width 0.088646)
		(layer "In4.Cu")
		(net "M_C_CPU0_SB_DQ<17>")
	)
	(arc
		(start 336.367882 -231.389936)
		(mid 336.085324 -231.465585)
		(end 335.802732 -231.389936)
		(width 0.088646)
		(layer "In4.Cu")
		(net "M_C_CPU0_SB_DQ<17>")
	)
	(arc
		(start 337.307682 -231.389936)
		(mid 337.029359 -231.465695)
		(end 336.749898 -231.394254)
		(width 0.088646)
		(layer "In4.Cu")
		(net "M_C_CPU0_SB_DQ<17>")
	)
	(arc
		(start 332.983332 -231.39019)
		(mid 332.796134 -231.340047)
		(end 332.608936 -231.39019)
		(width 0.088646)
		(layer "In4.Cu")
		(net "M_C_CPU0_SB_DQ<17>")
	)
	(segment
		(start 340.31428 -232.250234)
		(end 340.31428 -231.714548)
		(width 0.20066)
		(layer "F.Cu")
		(net "M_C_CPU0_SB_DQ<16>")
	)
	(segment
		(start 276.917912 -213.041738)
		(end 276.469094 -213.041738)
		(width 0.20066)
		(layer "F.Cu")
		(net "M_C_CPU0_SB_DQ<16>")
	)
	(segment
		(start 273.19986 -213.70544)
		(end 272.741136 -213.70544)
		(width 0.20066)
		(layer "F.Cu")
		(net "M_C_CPU0_SB_DQ<16>")
	)
	(segment
		(start 272.502376 -213.46668)
		(end 271.168114 -213.46668)
		(width 0.20066)
		(layer "F.Cu")
		(net "M_C_CPU0_SB_DQ<16>")
	)
	(segment
		(start 276.469094 -213.041738)
		(end 274.40001 -213.041738)
		(width 0.1016)
		(layer "F.Cu")
		(net "M_C_CPU0_SB_DQ<16>")
	)
	(segment
		(start 273.37258 -213.24316)
		(end 273.37258 -213.53272)
		(width 0.20066)
		(layer "F.Cu")
		(net "M_C_CPU0_SB_DQ<16>")
	)
	(segment
		(start 340.314534 -232.250488)
		(end 340.31428 -232.250234)
		(width 0.20066)
		(layer "F.Cu")
		(net "M_C_CPU0_SB_DQ<16>")
	)
	(segment
		(start 272.741136 -213.70544)
		(end 272.502376 -213.46668)
		(width 0.20066)
		(layer "F.Cu")
		(net "M_C_CPU0_SB_DQ<16>")
	)
	(segment
		(start 274.40001 -213.041738)
		(end 274.152106 -213.041738)
		(width 0.101854)
		(layer "F.Cu")
		(net "M_C_CPU0_SB_DQ<16>")
	)
	(segment
		(start 277.342854 -213.46668)
		(end 276.917912 -213.041738)
		(width 0.20066)
		(layer "F.Cu")
		(net "M_C_CPU0_SB_DQ<16>")
	)
	(segment
		(start 279.816814 -213.46668)
		(end 278.711914 -213.46668)
		(width 0.20066)
		(layer "F.Cu")
		(net "M_C_CPU0_SB_DQ<16>")
	)
	(segment
		(start 278.711914 -213.46668)
		(end 277.342854 -213.46668)
		(width 0.20066)
		(layer "F.Cu")
		(net "M_C_CPU0_SB_DQ<16>")
	)
	(segment
		(start 274.143978 -213.03361)
		(end 273.58213 -213.03361)
		(width 0.20066)
		(layer "F.Cu")
		(net "M_C_CPU0_SB_DQ<16>")
	)
	(segment
		(start 273.58213 -213.03361)
		(end 273.37258 -213.24316)
		(width 0.20066)
		(layer "F.Cu")
		(net "M_C_CPU0_SB_DQ<16>")
	)
	(segment
		(start 274.152106 -213.041738)
		(end 274.143978 -213.03361)
		(width 0.101854)
		(layer "F.Cu")
		(net "M_C_CPU0_SB_DQ<16>")
	)
	(segment
		(start 273.37258 -213.53272)
		(end 273.19986 -213.70544)
		(width 0.20066)
		(layer "F.Cu")
		(net "M_C_CPU0_SB_DQ<16>")
	)
	(segment
		(start 308.203854 -215.416638)
		(end 307.249322 -215.416638)
		(width 0.18288)
		(layer "In4.Cu")
		(net "M_C_CPU0_SB_DQ<16>")
	)
	(segment
		(start 308.894734 -216.504266)
		(end 308.57825 -216.504266)
		(width 0.18288)
		(layer "In4.Cu")
		(net "M_C_CPU0_SB_DQ<16>")
	)
	(segment
		(start 303.82972 -216.379806)
		(end 303.64684 -216.196926)
		(width 0.18288)
		(layer "In4.Cu")
		(net "M_C_CPU0_SB_DQ<16>")
	)
	(segment
		(start 311.05983 -216.205308)
		(end 310.27116 -215.416638)
		(width 0.18288)
		(layer "In4.Cu")
		(net "M_C_CPU0_SB_DQ<16>")
	)
	(segment
		(start 304.33772 -216.196926)
		(end 304.15484 -216.379806)
		(width 0.18288)
		(layer "In4.Cu")
		(net "M_C_CPU0_SB_DQ<16>")
	)
	(segment
		(start 302.792638 -215.591898)
		(end 298.48175 -215.591898)
		(width 0.18288)
		(layer "In4.Cu")
		(net "M_C_CPU0_SB_DQ<16>")
	)
	(segment
		(start 302.956722 -215.755982)
		(end 302.792638 -215.591898)
		(width 0.18288)
		(layer "In4.Cu")
		(net "M_C_CPU0_SB_DQ<16>")
	)
	(segment
		(start 336.843624 -232.20045)
		(end 336.837782 -232.204006)
		(width 0.088646)
		(layer "In4.Cu")
		(net "M_C_CPU0_SB_DQ<16>")
	)
	(segment
		(start 338.723224 -232.20045)
		(end 338.717382 -232.204006)
		(width 0.088646)
		(layer "In4.Cu")
		(net "M_C_CPU0_SB_DQ<16>")
	)
	(segment
		(start 305.5366 -216.379806)
		(end 305.21148 -216.379806)
		(width 0.18288)
		(layer "In4.Cu")
		(net "M_C_CPU0_SB_DQ<16>")
	)
	(segment
		(start 309.077614 -215.599518)
		(end 309.077614 -216.321386)
		(width 0.18288)
		(layer "In4.Cu")
		(net "M_C_CPU0_SB_DQ<16>")
	)
	(segment
		(start 303.46396 -215.755982)
		(end 302.956722 -215.755982)
		(width 0.18288)
		(layer "In4.Cu")
		(net "M_C_CPU0_SB_DQ<16>")
	)
	(segment
		(start 308.57825 -216.504266)
		(end 308.386734 -216.31275)
		(width 0.18288)
		(layer "In4.Cu")
		(net "M_C_CPU0_SB_DQ<16>")
	)
	(segment
		(start 303.64684 -216.196926)
		(end 303.64684 -215.938862)
		(width 0.18288)
		(layer "In4.Cu")
		(net "M_C_CPU0_SB_DQ<16>")
	)
	(segment
		(start 305.71948 -215.938862)
		(end 305.71948 -216.196926)
		(width 0.18288)
		(layer "In4.Cu")
		(net "M_C_CPU0_SB_DQ<16>")
	)
	(segment
		(start 309.260494 -215.416638)
		(end 309.077614 -215.599518)
		(width 0.18288)
		(layer "In4.Cu")
		(net "M_C_CPU0_SB_DQ<16>")
	)
	(segment
		(start 331.721714 -232.23474)
		(end 330.973684 -231.48671)
		(width 0.088646)
		(layer "In4.Cu")
		(net "M_C_CPU0_SB_DQ<16>")
	)
	(segment
		(start 298.48175 -215.591898)
		(end 297.631866 -216.441782)
		(width 0.18288)
		(layer "In4.Cu")
		(net "M_C_CPU0_SB_DQ<16>")
	)
	(segment
		(start 280.24201 -213.891876)
		(end 279.816814 -213.46668)
		(width 0.18288)
		(layer "In4.Cu")
		(net "M_C_CPU0_SB_DQ<16>")
	)
	(segment
		(start 314.94984 -219.200984)
		(end 311.954164 -216.205308)
		(width 0.18288)
		(layer "In4.Cu")
		(net "M_C_CPU0_SB_DQ<16>")
	)
	(segment
		(start 288.53257 -216.441782)
		(end 285.982664 -213.891876)
		(width 0.18288)
		(layer "In4.Cu")
		(net "M_C_CPU0_SB_DQ<16>")
	)
	(segment
		(start 304.84572 -215.755982)
		(end 304.5206 -215.755982)
		(width 0.18288)
		(layer "In4.Cu")
		(net "M_C_CPU0_SB_DQ<16>")
	)
	(segment
		(start 316.810136 -223.691958)
		(end 314.94984 -219.200984)
		(width 0.18288)
		(layer "In4.Cu")
		(net "M_C_CPU0_SB_DQ<16>")
	)
	(segment
		(start 335.897982 -232.204006)
		(end 335.898236 -232.204006)
		(width 0.088646)
		(layer "In4.Cu")
		(net "M_C_CPU0_SB_DQ<16>")
	)
	(segment
		(start 340.31428 -231.714548)
		(end 340.314026 -231.714802)
		(width 0.088646)
		(layer "In4.Cu")
		(net "M_C_CPU0_SB_DQ<16>")
	)
	(segment
		(start 336.837782 -232.204006)
		(end 336.83321 -232.206546)
		(width 0.088646)
		(layer "In4.Cu")
		(net "M_C_CPU0_SB_DQ<16>")
	)
	(segment
		(start 333.078582 -232.204006)
		(end 333.06385 -232.212642)
		(width 0.088646)
		(layer "In4.Cu")
		(net "M_C_CPU0_SB_DQ<16>")
	)
	(segment
		(start 306.909978 -215.755982)
		(end 305.90236 -215.755982)
		(width 0.18288)
		(layer "In4.Cu")
		(net "M_C_CPU0_SB_DQ<16>")
	)
	(segment
		(start 338.717382 -232.204006)
		(end 338.71154 -232.207308)
		(width 0.088646)
		(layer "In4.Cu")
		(net "M_C_CPU0_SB_DQ<16>")
	)
	(segment
		(start 330.648564 -231.48671)
		(end 324.604888 -231.48671)
		(width 0.18288)
		(layer "In4.Cu")
		(net "M_C_CPU0_SB_DQ<16>")
	)
	(segment
		(start 311.954164 -216.205308)
		(end 311.05983 -216.205308)
		(width 0.18288)
		(layer "In4.Cu")
		(net "M_C_CPU0_SB_DQ<16>")
	)
	(segment
		(start 308.386734 -215.599518)
		(end 308.203854 -215.416638)
		(width 0.18288)
		(layer "In4.Cu")
		(net "M_C_CPU0_SB_DQ<16>")
	)
	(segment
		(start 339.761068 -232.142792)
		(end 339.657182 -232.204006)
		(width 0.088646)
		(layer "In4.Cu")
		(net "M_C_CPU0_SB_DQ<16>")
	)
	(segment
		(start 297.631866 -216.441782)
		(end 288.53257 -216.441782)
		(width 0.18288)
		(layer "In4.Cu")
		(net "M_C_CPU0_SB_DQ<16>")
	)
	(segment
		(start 334.018636 -232.204006)
		(end 334.008222 -232.210102)
		(width 0.088646)
		(layer "In4.Cu")
		(net "M_C_CPU0_SB_DQ<16>")
	)
	(segment
		(start 305.90236 -215.755982)
		(end 305.71948 -215.938862)
		(width 0.18288)
		(layer "In4.Cu")
		(net "M_C_CPU0_SB_DQ<16>")
	)
	(segment
		(start 324.604888 -231.48671)
		(end 316.810136 -223.691958)
		(width 0.18288)
		(layer "In4.Cu")
		(net "M_C_CPU0_SB_DQ<16>")
	)
	(segment
		(start 337.777582 -232.204006)
		(end 337.77174 -232.207308)
		(width 0.088646)
		(layer "In4.Cu")
		(net "M_C_CPU0_SB_DQ<16>")
	)
	(segment
		(start 305.0286 -216.196926)
		(end 305.0286 -215.938862)
		(width 0.18288)
		(layer "In4.Cu")
		(net "M_C_CPU0_SB_DQ<16>")
	)
	(segment
		(start 305.21148 -216.379806)
		(end 305.0286 -216.196926)
		(width 0.18288)
		(layer "In4.Cu")
		(net "M_C_CPU0_SB_DQ<16>")
	)
	(segment
		(start 307.249322 -215.416638)
		(end 306.909978 -215.755982)
		(width 0.18288)
		(layer "In4.Cu")
		(net "M_C_CPU0_SB_DQ<16>")
	)
	(segment
		(start 310.27116 -215.416638)
		(end 309.260494 -215.416638)
		(width 0.18288)
		(layer "In4.Cu")
		(net "M_C_CPU0_SB_DQ<16>")
	)
	(segment
		(start 337.783424 -232.20045)
		(end 337.777582 -232.204006)
		(width 0.088646)
		(layer "In4.Cu")
		(net "M_C_CPU0_SB_DQ<16>")
	)
	(segment
		(start 304.33772 -215.938862)
		(end 304.33772 -216.196926)
		(width 0.18288)
		(layer "In4.Cu")
		(net "M_C_CPU0_SB_DQ<16>")
	)
	(segment
		(start 330.973684 -231.48671)
		(end 330.648564 -231.48671)
		(width 0.088646)
		(layer "In4.Cu")
		(net "M_C_CPU0_SB_DQ<16>")
	)
	(segment
		(start 305.71948 -216.196926)
		(end 305.5366 -216.379806)
		(width 0.18288)
		(layer "In4.Cu")
		(net "M_C_CPU0_SB_DQ<16>")
	)
	(segment
		(start 304.15484 -216.379806)
		(end 303.82972 -216.379806)
		(width 0.18288)
		(layer "In4.Cu")
		(net "M_C_CPU0_SB_DQ<16>")
	)
	(segment
		(start 309.077614 -216.321386)
		(end 308.894734 -216.504266)
		(width 0.18288)
		(layer "In4.Cu")
		(net "M_C_CPU0_SB_DQ<16>")
	)
	(segment
		(start 304.5206 -215.755982)
		(end 304.33772 -215.938862)
		(width 0.18288)
		(layer "In4.Cu")
		(net "M_C_CPU0_SB_DQ<16>")
	)
	(segment
		(start 305.0286 -215.938862)
		(end 304.84572 -215.755982)
		(width 0.18288)
		(layer "In4.Cu")
		(net "M_C_CPU0_SB_DQ<16>")
	)
	(segment
		(start 308.386734 -216.31275)
		(end 308.386734 -215.599518)
		(width 0.18288)
		(layer "In4.Cu")
		(net "M_C_CPU0_SB_DQ<16>")
	)
	(segment
		(start 285.982664 -213.891876)
		(end 280.24201 -213.891876)
		(width 0.18288)
		(layer "In4.Cu")
		(net "M_C_CPU0_SB_DQ<16>")
	)
	(segment
		(start 339.657182 -232.204006)
		(end 339.65134 -232.207308)
		(width 0.088646)
		(layer "In4.Cu")
		(net "M_C_CPU0_SB_DQ<16>")
	)
	(segment
		(start 303.64684 -215.938862)
		(end 303.46396 -215.755982)
		(width 0.18288)
		(layer "In4.Cu")
		(net "M_C_CPU0_SB_DQ<16>")
	)
	(arc
		(start 335.898236 -232.204006)
		(mid 335.615534 -232.279782)
		(end 335.332832 -232.204006)
		(width 0.088646)
		(layer "In4.Cu")
		(net "M_C_CPU0_SB_DQ<16>")
	)
	(arc
		(start 331.800962 -232.274872)
		(mid 331.758094 -232.261211)
		(end 331.721714 -232.23474)
		(width 0.088646)
		(layer "In4.Cu")
		(net "M_C_CPU0_SB_DQ<16>")
	)
	(arc
		(start 333.06385 -232.212642)
		(mid 332.787375 -232.279962)
		(end 332.513178 -232.204006)
		(width 0.088646)
		(layer "In4.Cu")
		(net "M_C_CPU0_SB_DQ<16>")
	)
	(arc
		(start 339.092032 -232.203752)
		(mid 338.908078 -232.153657)
		(end 338.723224 -232.20045)
		(width 0.088646)
		(layer "In4.Cu")
		(net "M_C_CPU0_SB_DQ<16>")
	)
	(arc
		(start 334.958436 -232.204006)
		(mid 334.675734 -232.279782)
		(end 334.393032 -232.204006)
		(width 0.088646)
		(layer "In4.Cu")
		(net "M_C_CPU0_SB_DQ<16>")
	)
	(arc
		(start 332.138782 -232.204006)
		(mid 332.020151 -232.255526)
		(end 331.89291 -232.278682)
		(width 0.088646)
		(layer "In4.Cu")
		(net "M_C_CPU0_SB_DQ<16>")
	)
	(arc
		(start 338.152232 -232.203752)
		(mid 337.968278 -232.153657)
		(end 337.783424 -232.20045)
		(width 0.088646)
		(layer "In4.Cu")
		(net "M_C_CPU0_SB_DQ<16>")
	)
	(arc
		(start 334.008222 -232.210102)
		(mid 333.72979 -232.279948)
		(end 333.452978 -232.204006)
		(width 0.088646)
		(layer "In4.Cu")
		(net "M_C_CPU0_SB_DQ<16>")
	)
	(arc
		(start 339.65134 -232.207308)
		(mid 339.371205 -232.279624)
		(end 339.092032 -232.203752)
		(width 0.088646)
		(layer "In4.Cu")
		(net "M_C_CPU0_SB_DQ<16>")
	)
	(arc
		(start 340.314026 -231.714802)
		(mid 340.051096 -231.946302)
		(end 339.761068 -232.142792)
		(width 0.088646)
		(layer "In4.Cu")
		(net "M_C_CPU0_SB_DQ<16>")
	)
	(arc
		(start 332.513178 -232.204006)
		(mid 332.32598 -232.153863)
		(end 332.138782 -232.204006)
		(width 0.088646)
		(layer "In4.Cu")
		(net "M_C_CPU0_SB_DQ<16>")
	)
	(arc
		(start 335.332832 -232.204006)
		(mid 335.145634 -232.153863)
		(end 334.958436 -232.204006)
		(width 0.088646)
		(layer "In4.Cu")
		(net "M_C_CPU0_SB_DQ<16>")
	)
	(arc
		(start 337.77174 -232.207308)
		(mid 337.491605 -232.279624)
		(end 337.212432 -232.203752)
		(width 0.088646)
		(layer "In4.Cu")
		(net "M_C_CPU0_SB_DQ<16>")
	)
	(arc
		(start 331.89291 -232.278682)
		(mid 331.846839 -232.279135)
		(end 331.800962 -232.274872)
		(width 0.088646)
		(layer "In4.Cu")
		(net "M_C_CPU0_SB_DQ<16>")
	)
	(arc
		(start 338.71154 -232.207308)
		(mid 338.431405 -232.279624)
		(end 338.152232 -232.203752)
		(width 0.088646)
		(layer "In4.Cu")
		(net "M_C_CPU0_SB_DQ<16>")
	)
	(arc
		(start 334.393032 -232.204006)
		(mid 334.205834 -232.153863)
		(end 334.018636 -232.204006)
		(width 0.088646)
		(layer "In4.Cu")
		(net "M_C_CPU0_SB_DQ<16>")
	)
	(arc
		(start 337.212432 -232.203752)
		(mid 337.028478 -232.153657)
		(end 336.843624 -232.20045)
		(width 0.088646)
		(layer "In4.Cu")
		(net "M_C_CPU0_SB_DQ<16>")
	)
	(arc
		(start 336.83321 -232.206546)
		(mid 336.552575 -232.279714)
		(end 336.272632 -232.204006)
		(width 0.088646)
		(layer "In4.Cu")
		(net "M_C_CPU0_SB_DQ<16>")
	)
	(arc
		(start 336.272632 -232.204006)
		(mid 336.085324 -232.153863)
		(end 335.897982 -232.204006)
		(width 0.088646)
		(layer "In4.Cu")
		(net "M_C_CPU0_SB_DQ<16>")
	)
	(arc
		(start 333.452978 -232.204006)
		(mid 333.26578 -232.153863)
		(end 333.078582 -232.204006)
		(width 0.088646)
		(layer "In4.Cu")
		(net "M_C_CPU0_SB_DQ<16>")
	)
	(segment
		(start 277.233888 -214.75573)
		(end 277.091394 -214.613236)
		(width 0.20066)
		(layer "F.Cu")
		(net "M_C_CPU0_SB_DQ<15>")
	)
	(segment
		(start 280.606246 -214.44077)
		(end 280.606246 -214.592408)
		(width 0.20066)
		(layer "F.Cu")
		(net "M_C_CPU0_SB_DQ<15>")
	)
	(segment
		(start 280.457148 -214.741506)
		(end 279.912826 -214.741506)
		(width 0.20066)
		(layer "F.Cu")
		(net "M_C_CPU0_SB_DQ<15>")
	)
	(segment
		(start 283.916882 -214.316564)
		(end 282.811982 -214.316564)
		(width 0.20066)
		(layer "F.Cu")
		(net "M_C_CPU0_SB_DQ<15>")
	)
	(segment
		(start 277.601934 -214.741506)
		(end 277.58771 -214.75573)
		(width 0.101854)
		(layer "F.Cu")
		(net "M_C_CPU0_SB_DQ<15>")
	)
	(segment
		(start 281.99588 -214.316564)
		(end 281.788362 -214.524082)
		(width 0.20066)
		(layer "F.Cu")
		(net "M_C_CPU0_SB_DQ<15>")
	)
	(segment
		(start 282.811982 -214.316564)
		(end 281.99588 -214.316564)
		(width 0.20066)
		(layer "F.Cu")
		(net "M_C_CPU0_SB_DQ<15>")
	)
	(segment
		(start 280.606246 -214.592408)
		(end 280.457148 -214.741506)
		(width 0.20066)
		(layer "F.Cu")
		(net "M_C_CPU0_SB_DQ<15>")
	)
	(segment
		(start 277.091394 -214.613236)
		(end 277.091394 -214.442548)
		(width 0.20066)
		(layer "F.Cu")
		(net "M_C_CPU0_SB_DQ<15>")
	)
	(segment
		(start 344.54338 -236.319822)
		(end 344.543634 -236.319568)
		(width 0.20066)
		(layer "F.Cu")
		(net "M_C_CPU0_SB_DQ<15>")
	)
	(segment
		(start 277.839932 -214.741506)
		(end 277.601934 -214.741506)
		(width 0.101854)
		(layer "F.Cu")
		(net "M_C_CPU0_SB_DQ<15>")
	)
	(segment
		(start 281.788362 -214.524082)
		(end 281.34183 -214.524082)
		(width 0.20066)
		(layer "F.Cu")
		(net "M_C_CPU0_SB_DQ<15>")
	)
	(segment
		(start 281.34183 -214.524082)
		(end 281.129994 -214.312246)
		(width 0.20066)
		(layer "F.Cu")
		(net "M_C_CPU0_SB_DQ<15>")
	)
	(segment
		(start 277.091394 -214.442548)
		(end 276.96541 -214.316564)
		(width 0.20066)
		(layer "F.Cu")
		(net "M_C_CPU0_SB_DQ<15>")
	)
	(segment
		(start 281.129994 -214.312246)
		(end 280.73477 -214.312246)
		(width 0.20066)
		(layer "F.Cu")
		(net "M_C_CPU0_SB_DQ<15>")
	)
	(segment
		(start 277.58771 -214.75573)
		(end 277.233888 -214.75573)
		(width 0.20066)
		(layer "F.Cu")
		(net "M_C_CPU0_SB_DQ<15>")
	)
	(segment
		(start 276.96541 -214.316564)
		(end 275.268182 -214.316564)
		(width 0.20066)
		(layer "F.Cu")
		(net "M_C_CPU0_SB_DQ<15>")
	)
	(segment
		(start 280.73477 -214.312246)
		(end 280.606246 -214.44077)
		(width 0.20066)
		(layer "F.Cu")
		(net "M_C_CPU0_SB_DQ<15>")
	)
	(segment
		(start 344.543634 -236.319568)
		(end 344.543634 -235.783882)
		(width 0.20066)
		(layer "F.Cu")
		(net "M_C_CPU0_SB_DQ<15>")
	)
	(segment
		(start 279.912826 -214.741506)
		(end 277.839932 -214.741506)
		(width 0.1016)
		(layer "F.Cu")
		(net "M_C_CPU0_SB_DQ<15>")
	)
	(segment
		(start 308.50459 -216.684098)
		(end 307.25491 -216.684098)
		(width 0.18288)
		(layer "In6.Cu")
		(net "M_C_CPU0_SB_DQ<15>")
	)
	(segment
		(start 333.462376 -234.475528)
		(end 333.453486 -234.480862)
		(width 0.088646)
		(layer "In6.Cu")
		(net "M_C_CPU0_SB_DQ<15>")
	)
	(segment
		(start 290.068 -215.048592)
		(end 289.88512 -215.231472)
		(width 0.18288)
		(layer "In6.Cu")
		(net "M_C_CPU0_SB_DQ<15>")
	)
	(segment
		(start 341.066882 -235.294424)
		(end 341.05215 -235.285788)
		(width 0.088646)
		(layer "In6.Cu")
		(net "M_C_CPU0_SB_DQ<15>")
	)
	(segment
		(start 314.295028 -219.918534)
		(end 312.805826 -219.918534)
		(width 0.18288)
		(layer "In6.Cu")
		(net "M_C_CPU0_SB_DQ<15>")
	)
	(segment
		(start 294.724074 -215.593168)
		(end 293.77386 -216.543382)
		(width 0.18288)
		(layer "In6.Cu")
		(net "M_C_CPU0_SB_DQ<15>")
	)
	(segment
		(start 338.632546 -235.288328)
		(end 338.622132 -235.294424)
		(width 0.088646)
		(layer "In6.Cu")
		(net "M_C_CPU0_SB_DQ<15>")
	)
	(segment
		(start 312.805826 -219.918534)
		(end 311.310274 -218.422982)
		(width 0.18288)
		(layer "In6.Cu")
		(net "M_C_CPU0_SB_DQ<15>")
	)
	(segment
		(start 310.243474 -218.422982)
		(end 308.50459 -216.684098)
		(width 0.18288)
		(layer "In6.Cu")
		(net "M_C_CPU0_SB_DQ<15>")
	)
	(segment
		(start 301.564294 -216.478358)
		(end 301.564294 -216.184226)
		(width 0.18288)
		(layer "In6.Cu")
		(net "M_C_CPU0_SB_DQ<15>")
	)
	(segment
		(start 340.127082 -235.294424)
		(end 340.11235 -235.285788)
		(width 0.088646)
		(layer "In6.Cu")
		(net "M_C_CPU0_SB_DQ<15>")
	)
	(segment
		(start 332.513432 -234.480608)
		(end 332.50505 -234.485434)
		(width 0.088646)
		(layer "In6.Cu")
		(net "M_C_CPU0_SB_DQ<15>")
	)
	(segment
		(start 342.946482 -235.294424)
		(end 342.93175 -235.285788)
		(width 0.088646)
		(layer "In6.Cu")
		(net "M_C_CPU0_SB_DQ<15>")
	)
	(segment
		(start 318.553084 -224.17659)
		(end 314.295028 -219.918534)
		(width 0.18288)
		(layer "In6.Cu")
		(net "M_C_CPU0_SB_DQ<15>")
	)
	(segment
		(start 304.754026 -216.13114)
		(end 304.571146 -216.31402)
		(width 0.18288)
		(layer "In6.Cu")
		(net "M_C_CPU0_SB_DQ<15>")
	)
	(segment
		(start 335.802732 -235.294424)
		(end 335.79181 -235.300774)
		(width 0.088646)
		(layer "In6.Cu")
		(net "M_C_CPU0_SB_DQ<15>")
	)
	(segment
		(start 305.627786 -216.31402)
		(end 305.444906 -216.13114)
		(width 0.18288)
		(layer "In6.Cu")
		(net "M_C_CPU0_SB_DQ<15>")
	)
	(segment
		(start 301.056294 -216.001346)
		(end 300.873414 -216.184226)
		(width 0.18288)
		(layer "In6.Cu")
		(net "M_C_CPU0_SB_DQ<15>")
	)
	(segment
		(start 299.743368 -216.441782)
		(end 298.236386 -216.441782)
		(width 0.18288)
		(layer "In6.Cu")
		(net "M_C_CPU0_SB_DQ<15>")
	)
	(segment
		(start 301.381414 -216.001346)
		(end 301.056294 -216.001346)
		(width 0.18288)
		(layer "In6.Cu")
		(net "M_C_CPU0_SB_DQ<15>")
	)
	(segment
		(start 305.444906 -216.13114)
		(end 305.444906 -215.701372)
		(width 0.18288)
		(layer "In6.Cu")
		(net "M_C_CPU0_SB_DQ<15>")
	)
	(segment
		(start 335.428336 -235.294678)
		(end 335.419446 -235.289598)
		(width 0.088646)
		(layer "In6.Cu")
		(net "M_C_CPU0_SB_DQ<15>")
	)
	(segment
		(start 292.113716 -216.543382)
		(end 291.46119 -215.890856)
		(width 0.18288)
		(layer "In6.Cu")
		(net "M_C_CPU0_SB_DQ<15>")
	)
	(segment
		(start 332.51902 -234.477306)
		(end 332.513432 -234.480608)
		(width 0.088646)
		(layer "In6.Cu")
		(net "M_C_CPU0_SB_DQ<15>")
	)
	(segment
		(start 324.017386 -232.401364)
		(end 318.553084 -226.937062)
		(width 0.18288)
		(layer "In6.Cu")
		(net "M_C_CPU0_SB_DQ<15>")
	)
	(segment
		(start 342.006682 -235.294424)
		(end 341.99195 -235.285788)
		(width 0.088646)
		(layer "In6.Cu")
		(net "M_C_CPU0_SB_DQ<15>")
	)
	(segment
		(start 291.46119 -215.890856)
		(end 290.75888 -215.890856)
		(width 0.18288)
		(layer "In6.Cu")
		(net "M_C_CPU0_SB_DQ<15>")
	)
	(segment
		(start 305.444906 -215.701372)
		(end 305.262026 -215.518492)
		(width 0.18288)
		(layer "In6.Cu")
		(net "M_C_CPU0_SB_DQ<15>")
	)
	(segment
		(start 334.027018 -234.485434)
		(end 334.018636 -234.480608)
		(width 0.088646)
		(layer "In6.Cu")
		(net "M_C_CPU0_SB_DQ<15>")
	)
	(segment
		(start 289.88512 -215.231472)
		(end 289.88512 -215.707976)
		(width 0.18288)
		(layer "In6.Cu")
		(net "M_C_CPU0_SB_DQ<15>")
	)
	(segment
		(start 331.898244 -234.115356)
		(end 331.898244 -233.566462)
		(width 0.088646)
		(layer "In6.Cu")
		(net "M_C_CPU0_SB_DQ<15>")
	)
	(segment
		(start 334.403192 -234.474512)
		(end 334.392778 -234.480608)
		(width 0.088646)
		(layer "In6.Cu")
		(net "M_C_CPU0_SB_DQ<15>")
	)
	(segment
		(start 331.999844 -234.36072)
		(end 331.898244 -234.115356)
		(width 0.088646)
		(layer "In6.Cu")
		(net "M_C_CPU0_SB_DQ<15>")
	)
	(segment
		(start 306.884832 -216.31402)
		(end 305.627786 -216.31402)
		(width 0.18288)
		(layer "In6.Cu")
		(net "M_C_CPU0_SB_DQ<15>")
	)
	(segment
		(start 311.310274 -218.422982)
		(end 310.243474 -218.422982)
		(width 0.18288)
		(layer "In6.Cu")
		(net "M_C_CPU0_SB_DQ<15>")
	)
	(segment
		(start 338.247736 -235.294424)
		(end 338.237322 -235.288328)
		(width 0.088646)
		(layer "In6.Cu")
		(net "M_C_CPU0_SB_DQ<15>")
	)
	(segment
		(start 318.553084 -226.937062)
		(end 318.553084 -224.17659)
		(width 0.18288)
		(layer "In6.Cu")
		(net "M_C_CPU0_SB_DQ<15>")
	)
	(segment
		(start 300.873414 -216.184226)
		(end 300.873414 -216.478358)
		(width 0.18288)
		(layer "In6.Cu")
		(net "M_C_CPU0_SB_DQ<15>")
	)
	(segment
		(start 332.060804 -234.42168)
		(end 331.999844 -234.36072)
		(width 0.088646)
		(layer "In6.Cu")
		(net "M_C_CPU0_SB_DQ<15>")
	)
	(segment
		(start 304.571146 -216.31402)
		(end 303.399698 -216.31402)
		(width 0.18288)
		(layer "In6.Cu")
		(net "M_C_CPU0_SB_DQ<15>")
	)
	(segment
		(start 290.576 -215.707976)
		(end 290.576 -215.231472)
		(width 0.18288)
		(layer "In6.Cu")
		(net "M_C_CPU0_SB_DQ<15>")
	)
	(segment
		(start 284.595062 -214.994744)
		(end 283.916882 -214.316564)
		(width 0.18288)
		(layer "In6.Cu")
		(net "M_C_CPU0_SB_DQ<15>")
	)
	(segment
		(start 290.75888 -215.890856)
		(end 290.576 -215.707976)
		(width 0.18288)
		(layer "In6.Cu")
		(net "M_C_CPU0_SB_DQ<15>")
	)
	(segment
		(start 303.399698 -216.31402)
		(end 303.05248 -216.661238)
		(width 0.18288)
		(layer "In6.Cu")
		(net "M_C_CPU0_SB_DQ<15>")
	)
	(segment
		(start 307.25491 -216.684098)
		(end 306.884832 -216.31402)
		(width 0.18288)
		(layer "In6.Cu")
		(net "M_C_CPU0_SB_DQ<15>")
	)
	(segment
		(start 289.88512 -215.707976)
		(end 289.70224 -215.890856)
		(width 0.18288)
		(layer "In6.Cu")
		(net "M_C_CPU0_SB_DQ<15>")
	)
	(segment
		(start 331.898244 -233.566462)
		(end 330.733146 -232.401364)
		(width 0.088646)
		(layer "In6.Cu")
		(net "M_C_CPU0_SB_DQ<15>")
	)
	(segment
		(start 300.690534 -216.661238)
		(end 299.962824 -216.661238)
		(width 0.18288)
		(layer "In6.Cu")
		(net "M_C_CPU0_SB_DQ<15>")
	)
	(segment
		(start 289.01136 -215.890856)
		(end 288.115248 -214.994744)
		(width 0.18288)
		(layer "In6.Cu")
		(net "M_C_CPU0_SB_DQ<15>")
	)
	(segment
		(start 299.962824 -216.661238)
		(end 299.743368 -216.441782)
		(width 0.18288)
		(layer "In6.Cu")
		(net "M_C_CPU0_SB_DQ<15>")
	)
	(segment
		(start 300.873414 -216.478358)
		(end 300.690534 -216.661238)
		(width 0.18288)
		(layer "In6.Cu")
		(net "M_C_CPU0_SB_DQ<15>")
	)
	(segment
		(start 337.307682 -235.294424)
		(end 337.29295 -235.285788)
		(width 0.088646)
		(layer "In6.Cu")
		(net "M_C_CPU0_SB_DQ<15>")
	)
	(segment
		(start 330.572364 -232.401364)
		(end 324.017386 -232.401364)
		(width 0.18288)
		(layer "In6.Cu")
		(net "M_C_CPU0_SB_DQ<15>")
	)
	(segment
		(start 334.964532 -234.484164)
		(end 334.958436 -234.480608)
		(width 0.088646)
		(layer "In6.Cu")
		(net "M_C_CPU0_SB_DQ<15>")
	)
	(segment
		(start 298.236386 -216.441782)
		(end 297.387772 -215.593168)
		(width 0.18288)
		(layer "In6.Cu")
		(net "M_C_CPU0_SB_DQ<15>")
	)
	(segment
		(start 330.733146 -232.401364)
		(end 330.572364 -232.401364)
		(width 0.088646)
		(layer "In6.Cu")
		(net "M_C_CPU0_SB_DQ<15>")
	)
	(segment
		(start 290.576 -215.231472)
		(end 290.39312 -215.048592)
		(width 0.18288)
		(layer "In6.Cu")
		(net "M_C_CPU0_SB_DQ<15>")
	)
	(segment
		(start 297.387772 -215.593168)
		(end 294.724074 -215.593168)
		(width 0.18288)
		(layer "In6.Cu")
		(net "M_C_CPU0_SB_DQ<15>")
	)
	(segment
		(start 304.936906 -215.518492)
		(end 304.754026 -215.701372)
		(width 0.18288)
		(layer "In6.Cu")
		(net "M_C_CPU0_SB_DQ<15>")
	)
	(segment
		(start 293.77386 -216.543382)
		(end 292.113716 -216.543382)
		(width 0.18288)
		(layer "In6.Cu")
		(net "M_C_CPU0_SB_DQ<15>")
	)
	(segment
		(start 303.05248 -216.661238)
		(end 301.747174 -216.661238)
		(width 0.18288)
		(layer "In6.Cu")
		(net "M_C_CPU0_SB_DQ<15>")
	)
	(segment
		(start 305.262026 -215.518492)
		(end 304.936906 -215.518492)
		(width 0.18288)
		(layer "In6.Cu")
		(net "M_C_CPU0_SB_DQ<15>")
	)
	(segment
		(start 301.747174 -216.661238)
		(end 301.564294 -216.478358)
		(width 0.18288)
		(layer "In6.Cu")
		(net "M_C_CPU0_SB_DQ<15>")
	)
	(segment
		(start 290.39312 -215.048592)
		(end 290.068 -215.048592)
		(width 0.18288)
		(layer "In6.Cu")
		(net "M_C_CPU0_SB_DQ<15>")
	)
	(segment
		(start 288.115248 -214.994744)
		(end 284.595062 -214.994744)
		(width 0.18288)
		(layer "In6.Cu")
		(net "M_C_CPU0_SB_DQ<15>")
	)
	(segment
		(start 304.754026 -215.701372)
		(end 304.754026 -216.13114)
		(width 0.18288)
		(layer "In6.Cu")
		(net "M_C_CPU0_SB_DQ<15>")
	)
	(segment
		(start 289.70224 -215.890856)
		(end 289.01136 -215.890856)
		(width 0.18288)
		(layer "In6.Cu")
		(net "M_C_CPU0_SB_DQ<15>")
	)
	(segment
		(start 336.367882 -235.294424)
		(end 336.357468 -235.288328)
		(width 0.088646)
		(layer "In6.Cu")
		(net "M_C_CPU0_SB_DQ<15>")
	)
	(segment
		(start 301.564294 -216.184226)
		(end 301.381414 -216.001346)
		(width 0.18288)
		(layer "In6.Cu")
		(net "M_C_CPU0_SB_DQ<15>")
	)
	(segment
		(start 333.453486 -234.480862)
		(end 333.445104 -234.485688)
		(width 0.088646)
		(layer "In6.Cu")
		(net "M_C_CPU0_SB_DQ<15>")
	)
	(arc
		(start 344.543634 -235.783882)
		(mid 343.92438 -235.395252)
		(end 343.195402 -235.339382)
		(width 0.088646)
		(layer "In6.Cu")
		(net "M_C_CPU0_SB_DQ<15>")
	)
	(arc
		(start 333.445104 -234.485688)
		(mid 333.261342 -234.531088)
		(end 333.078836 -234.480862)
		(width 0.088646)
		(layer "In6.Cu")
		(net "M_C_CPU0_SB_DQ<15>")
	)
	(arc
		(start 340.501478 -235.294424)
		(mid 340.31428 -235.344567)
		(end 340.127082 -235.294424)
		(width 0.088646)
		(layer "In6.Cu")
		(net "M_C_CPU0_SB_DQ<15>")
	)
	(arc
		(start 336.357468 -235.288328)
		(mid 336.07929 -235.218605)
		(end 335.802732 -235.294424)
		(width 0.088646)
		(layer "In6.Cu")
		(net "M_C_CPU0_SB_DQ<15>")
	)
	(arc
		(start 333.078836 -234.480862)
		(mid 332.799408 -234.40497)
		(end 332.51902 -234.477306)
		(width 0.088646)
		(layer "In6.Cu")
		(net "M_C_CPU0_SB_DQ<15>")
	)
	(arc
		(start 332.138782 -234.480608)
		(mid 332.097862 -234.453698)
		(end 332.060804 -234.42168)
		(width 0.088646)
		(layer "In6.Cu")
		(net "M_C_CPU0_SB_DQ<15>")
	)
	(arc
		(start 343.195402 -235.339382)
		(mid 343.067042 -235.338527)
		(end 342.946482 -235.294424)
		(width 0.088646)
		(layer "In6.Cu")
		(net "M_C_CPU0_SB_DQ<15>")
	)
	(arc
		(start 332.50505 -234.485434)
		(mid 332.321288 -234.530834)
		(end 332.138782 -234.480608)
		(width 0.088646)
		(layer "In6.Cu")
		(net "M_C_CPU0_SB_DQ<15>")
	)
	(arc
		(start 335.419446 -235.289598)
		(mid 335.288532 -235.153238)
		(end 335.240884 -234.97032)
		(width 0.088646)
		(layer "In6.Cu")
		(net "M_C_CPU0_SB_DQ<15>")
	)
	(arc
		(start 342.381078 -235.294424)
		(mid 342.19388 -235.344567)
		(end 342.006682 -235.294424)
		(width 0.088646)
		(layer "In6.Cu")
		(net "M_C_CPU0_SB_DQ<15>")
	)
	(arc
		(start 334.018636 -234.480608)
		(mid 333.741164 -234.40489)
		(end 333.462376 -234.475528)
		(width 0.088646)
		(layer "In6.Cu")
		(net "M_C_CPU0_SB_DQ<15>")
	)
	(arc
		(start 334.392778 -234.480608)
		(mid 334.210527 -234.530719)
		(end 334.027018 -234.485434)
		(width 0.088646)
		(layer "In6.Cu")
		(net "M_C_CPU0_SB_DQ<15>")
	)
	(arc
		(start 339.561678 -235.294424)
		(mid 339.37448 -235.344567)
		(end 339.187282 -235.294424)
		(width 0.088646)
		(layer "In6.Cu")
		(net "M_C_CPU0_SB_DQ<15>")
	)
	(arc
		(start 341.99195 -235.285788)
		(mid 341.715475 -235.218468)
		(end 341.441278 -235.294424)
		(width 0.088646)
		(layer "In6.Cu")
		(net "M_C_CPU0_SB_DQ<15>")
	)
	(arc
		(start 339.187282 -235.294424)
		(mid 338.910723 -235.218681)
		(end 338.632546 -235.288328)
		(width 0.088646)
		(layer "In6.Cu")
		(net "M_C_CPU0_SB_DQ<15>")
	)
	(arc
		(start 341.441278 -235.294424)
		(mid 341.25408 -235.344567)
		(end 341.066882 -235.294424)
		(width 0.088646)
		(layer "In6.Cu")
		(net "M_C_CPU0_SB_DQ<15>")
	)
	(arc
		(start 335.79181 -235.300774)
		(mid 335.60928 -235.344798)
		(end 335.428336 -235.294678)
		(width 0.088646)
		(layer "In6.Cu")
		(net "M_C_CPU0_SB_DQ<15>")
	)
	(arc
		(start 337.682078 -235.294424)
		(mid 337.49488 -235.344567)
		(end 337.307682 -235.294424)
		(width 0.088646)
		(layer "In6.Cu")
		(net "M_C_CPU0_SB_DQ<15>")
	)
	(arc
		(start 338.237322 -235.288328)
		(mid 337.95889 -235.218482)
		(end 337.682078 -235.294424)
		(width 0.088646)
		(layer "In6.Cu")
		(net "M_C_CPU0_SB_DQ<15>")
	)
	(arc
		(start 337.29295 -235.285788)
		(mid 337.016475 -235.218468)
		(end 336.742278 -235.294424)
		(width 0.088646)
		(layer "In6.Cu")
		(net "M_C_CPU0_SB_DQ<15>")
	)
	(arc
		(start 340.11235 -235.285788)
		(mid 339.835875 -235.218468)
		(end 339.561678 -235.294424)
		(width 0.088646)
		(layer "In6.Cu")
		(net "M_C_CPU0_SB_DQ<15>")
	)
	(arc
		(start 341.05215 -235.285788)
		(mid 340.775675 -235.218468)
		(end 340.501478 -235.294424)
		(width 0.088646)
		(layer "In6.Cu")
		(net "M_C_CPU0_SB_DQ<15>")
	)
	(arc
		(start 336.742278 -235.294424)
		(mid 336.55508 -235.344567)
		(end 336.367882 -235.294424)
		(width 0.088646)
		(layer "In6.Cu")
		(net "M_C_CPU0_SB_DQ<15>")
	)
	(arc
		(start 342.93175 -235.285788)
		(mid 342.655275 -235.218468)
		(end 342.381078 -235.294424)
		(width 0.088646)
		(layer "In6.Cu")
		(net "M_C_CPU0_SB_DQ<15>")
	)
	(arc
		(start 335.240884 -234.97032)
		(mid 335.167031 -234.690674)
		(end 334.964532 -234.484164)
		(width 0.088646)
		(layer "In6.Cu")
		(net "M_C_CPU0_SB_DQ<15>")
	)
	(arc
		(start 334.958436 -234.480608)
		(mid 334.681623 -234.404738)
		(end 334.403192 -234.474512)
		(width 0.088646)
		(layer "In6.Cu")
		(net "M_C_CPU0_SB_DQ<15>")
	)
	(arc
		(start 338.622132 -235.294424)
		(mid 338.434934 -235.344567)
		(end 338.247736 -235.294424)
		(width 0.088646)
		(layer "In6.Cu")
		(net "M_C_CPU0_SB_DQ<15>")
	)
	(segment
		(start 345.01328 -237.133638)
		(end 345.01328 -236.597952)
		(width 0.20066)
		(layer "F.Cu")
		(net "M_C_CPU0_SB_DQ<14>")
	)
	(segment
		(start 277.59787 -215.591644)
		(end 277.58771 -215.581484)
		(width 0.101854)
		(layer "F.Cu")
		(net "M_C_CPU0_SB_DQ<14>")
	)
	(segment
		(start 345.013534 -237.133892)
		(end 345.01328 -237.133638)
		(width 0.20066)
		(layer "F.Cu")
		(net "M_C_CPU0_SB_DQ<14>")
	)
	(segment
		(start 282.811982 -216.016586)
		(end 281.497278 -216.016586)
		(width 0.20066)
		(layer "F.Cu")
		(net "M_C_CPU0_SB_DQ<14>")
	)
	(segment
		(start 279.912826 -215.591644)
		(end 277.852886 -215.591644)
		(width 0.1016)
		(layer "F.Cu")
		(net "M_C_CPU0_SB_DQ<14>")
	)
	(segment
		(start 280.689558 -216.061036)
		(end 280.689558 -215.735408)
		(width 0.20066)
		(layer "F.Cu")
		(net "M_C_CPU0_SB_DQ<14>")
	)
	(segment
		(start 280.856944 -216.228422)
		(end 280.689558 -216.061036)
		(width 0.20066)
		(layer "F.Cu")
		(net "M_C_CPU0_SB_DQ<14>")
	)
	(segment
		(start 280.689558 -215.735408)
		(end 280.545794 -215.591644)
		(width 0.20066)
		(layer "F.Cu")
		(net "M_C_CPU0_SB_DQ<14>")
	)
	(segment
		(start 283.916882 -216.016586)
		(end 282.811982 -216.016586)
		(width 0.20066)
		(layer "F.Cu")
		(net "M_C_CPU0_SB_DQ<14>")
	)
	(segment
		(start 277.58771 -215.581484)
		(end 276.850348 -215.581484)
		(width 0.20066)
		(layer "F.Cu")
		(net "M_C_CPU0_SB_DQ<14>")
	)
	(segment
		(start 280.545794 -215.591644)
		(end 279.912826 -215.591644)
		(width 0.20066)
		(layer "F.Cu")
		(net "M_C_CPU0_SB_DQ<14>")
	)
	(segment
		(start 276.850348 -215.581484)
		(end 276.415246 -216.016586)
		(width 0.20066)
		(layer "F.Cu")
		(net "M_C_CPU0_SB_DQ<14>")
	)
	(segment
		(start 281.285442 -216.228422)
		(end 280.856944 -216.228422)
		(width 0.20066)
		(layer "F.Cu")
		(net "M_C_CPU0_SB_DQ<14>")
	)
	(segment
		(start 281.497278 -216.016586)
		(end 281.285442 -216.228422)
		(width 0.20066)
		(layer "F.Cu")
		(net "M_C_CPU0_SB_DQ<14>")
	)
	(segment
		(start 277.852886 -215.591644)
		(end 277.59787 -215.591644)
		(width 0.101854)
		(layer "F.Cu")
		(net "M_C_CPU0_SB_DQ<14>")
	)
	(segment
		(start 276.415246 -216.016586)
		(end 275.268182 -216.016586)
		(width 0.20066)
		(layer "F.Cu")
		(net "M_C_CPU0_SB_DQ<14>")
	)
	(segment
		(start 301.291244 -218.809062)
		(end 301.108364 -218.991942)
		(width 0.18288)
		(layer "In6.Cu")
		(net "M_C_CPU0_SB_DQ<14>")
	)
	(segment
		(start 333.932276 -235.289344)
		(end 333.923386 -235.294678)
		(width 0.088646)
		(layer "In6.Cu")
		(net "M_C_CPU0_SB_DQ<14>")
	)
	(segment
		(start 332.617064 -235.299504)
		(end 332.608682 -235.294678)
		(width 0.088646)
		(layer "In6.Cu")
		(net "M_C_CPU0_SB_DQ<14>")
	)
	(segment
		(start 286.437578 -216.567512)
		(end 286.437578 -216.284556)
		(width 0.18288)
		(layer "In6.Cu")
		(net "M_C_CPU0_SB_DQ<14>")
	)
	(segment
		(start 323.533008 -233.397044)
		(end 317.557404 -227.42144)
		(width 0.18288)
		(layer "In6.Cu")
		(net "M_C_CPU0_SB_DQ<14>")
	)
	(segment
		(start 331.664056 -234.682538)
		(end 331.664056 -234.580684)
		(width 0.088646)
		(layer "In6.Cu")
		(net "M_C_CPU0_SB_DQ<14>")
	)
	(segment
		(start 330.878434 -233.397044)
		(end 330.572364 -233.397044)
		(width 0.088646)
		(layer "In6.Cu")
		(net "M_C_CPU0_SB_DQ<14>")
	)
	(segment
		(start 301.474124 -218.215972)
		(end 301.291244 -218.398852)
		(width 0.18288)
		(layer "In6.Cu")
		(net "M_C_CPU0_SB_DQ<14>")
	)
	(segment
		(start 300.783244 -218.991942)
		(end 300.600364 -218.809062)
		(width 0.18288)
		(layer "In6.Cu")
		(net "M_C_CPU0_SB_DQ<14>")
	)
	(segment
		(start 299.726604 -218.991942)
		(end 298.346114 -218.991942)
		(width 0.18288)
		(layer "In6.Cu")
		(net "M_C_CPU0_SB_DQ<14>")
	)
	(segment
		(start 298.346114 -218.991942)
		(end 296.645838 -217.291666)
		(width 0.18288)
		(layer "In6.Cu")
		(net "M_C_CPU0_SB_DQ<14>")
	)
	(segment
		(start 309.465472 -219.51442)
		(end 308.286658 -218.335606)
		(width 0.18288)
		(layer "In6.Cu")
		(net "M_C_CPU0_SB_DQ<14>")
	)
	(segment
		(start 330.572364 -233.397044)
		(end 323.533008 -233.397044)
		(width 0.18288)
		(layer "In6.Cu")
		(net "M_C_CPU0_SB_DQ<14>")
	)
	(segment
		(start 285.563818 -216.750392)
		(end 284.650688 -216.750392)
		(width 0.18288)
		(layer "In6.Cu")
		(net "M_C_CPU0_SB_DQ<14>")
	)
	(segment
		(start 313.067446 -221.657926)
		(end 311.85866 -220.44914)
		(width 0.18288)
		(layer "In6.Cu")
		(net "M_C_CPU0_SB_DQ<14>")
	)
	(segment
		(start 290.07562 -217.393266)
		(end 288.954972 -217.393266)
		(width 0.18288)
		(layer "In6.Cu")
		(net "M_C_CPU0_SB_DQ<14>")
	)
	(segment
		(start 301.799244 -218.215972)
		(end 301.474124 -218.215972)
		(width 0.18288)
		(layer "In6.Cu")
		(net "M_C_CPU0_SB_DQ<14>")
	)
	(segment
		(start 332.32598 -235.218986)
		(end 332.200504 -235.218986)
		(width 0.088646)
		(layer "In6.Cu")
		(net "M_C_CPU0_SB_DQ<14>")
	)
	(segment
		(start 300.417484 -218.215972)
		(end 300.092364 -218.215972)
		(width 0.18288)
		(layer "In6.Cu")
		(net "M_C_CPU0_SB_DQ<14>")
	)
	(segment
		(start 333.54899 -235.294678)
		(end 333.538576 -235.288582)
		(width 0.088646)
		(layer "In6.Cu")
		(net "M_C_CPU0_SB_DQ<14>")
	)
	(segment
		(start 284.650688 -216.750392)
		(end 283.916882 -216.016586)
		(width 0.18288)
		(layer "In6.Cu")
		(net "M_C_CPU0_SB_DQ<14>")
	)
	(segment
		(start 285.746698 -216.284556)
		(end 285.746698 -216.567512)
		(width 0.18288)
		(layer "In6.Cu")
		(net "M_C_CPU0_SB_DQ<14>")
	)
	(segment
		(start 301.982124 -218.398852)
		(end 301.799244 -218.215972)
		(width 0.18288)
		(layer "In6.Cu")
		(net "M_C_CPU0_SB_DQ<14>")
	)
	(segment
		(start 300.092364 -218.215972)
		(end 299.909484 -218.398852)
		(width 0.18288)
		(layer "In6.Cu")
		(net "M_C_CPU0_SB_DQ<14>")
	)
	(segment
		(start 301.982124 -218.809062)
		(end 301.982124 -218.398852)
		(width 0.18288)
		(layer "In6.Cu")
		(net "M_C_CPU0_SB_DQ<14>")
	)
	(segment
		(start 340.046564 -236.099604)
		(end 340.031832 -236.10824)
		(width 0.088646)
		(layer "In6.Cu")
		(net "M_C_CPU0_SB_DQ<14>")
	)
	(segment
		(start 286.620458 -216.750392)
		(end 286.437578 -216.567512)
		(width 0.18288)
		(layer "In6.Cu")
		(net "M_C_CPU0_SB_DQ<14>")
	)
	(segment
		(start 300.600364 -218.398852)
		(end 300.417484 -218.215972)
		(width 0.18288)
		(layer "In6.Cu")
		(net "M_C_CPU0_SB_DQ<14>")
	)
	(segment
		(start 300.600364 -218.809062)
		(end 300.600364 -218.398852)
		(width 0.18288)
		(layer "In6.Cu")
		(net "M_C_CPU0_SB_DQ<14>")
	)
	(segment
		(start 339.102192 -236.102144)
		(end 339.091778 -236.10824)
		(width 0.088646)
		(layer "In6.Cu")
		(net "M_C_CPU0_SB_DQ<14>")
	)
	(segment
		(start 286.254698 -216.101676)
		(end 285.929578 -216.101676)
		(width 0.18288)
		(layer "In6.Cu")
		(net "M_C_CPU0_SB_DQ<14>")
	)
	(segment
		(start 296.645838 -217.291666)
		(end 294.590724 -217.291666)
		(width 0.18288)
		(layer "In6.Cu")
		(net "M_C_CPU0_SB_DQ<14>")
	)
	(segment
		(start 291.01923 -218.336876)
		(end 290.07562 -217.393266)
		(width 0.18288)
		(layer "In6.Cu")
		(net "M_C_CPU0_SB_DQ<14>")
	)
	(segment
		(start 310.289448 -219.51442)
		(end 309.465472 -219.51442)
		(width 0.18288)
		(layer "In6.Cu")
		(net "M_C_CPU0_SB_DQ<14>")
	)
	(segment
		(start 338.162646 -236.102144)
		(end 338.152232 -236.10824)
		(width 0.088646)
		(layer "In6.Cu")
		(net "M_C_CPU0_SB_DQ<14>")
	)
	(segment
		(start 335.346548 -236.100366)
		(end 335.332832 -236.108494)
		(width 0.088646)
		(layer "In6.Cu")
		(net "M_C_CPU0_SB_DQ<14>")
	)
	(segment
		(start 311.85866 -220.44914)
		(end 311.224168 -220.44914)
		(width 0.18288)
		(layer "In6.Cu")
		(net "M_C_CPU0_SB_DQ<14>")
	)
	(segment
		(start 308.286658 -218.335606)
		(end 303.761648 -218.335606)
		(width 0.18288)
		(layer "In6.Cu")
		(net "M_C_CPU0_SB_DQ<14>")
	)
	(segment
		(start 301.108364 -218.991942)
		(end 300.783244 -218.991942)
		(width 0.18288)
		(layer "In6.Cu")
		(net "M_C_CPU0_SB_DQ<14>")
	)
	(segment
		(start 299.909484 -218.809062)
		(end 299.726604 -218.991942)
		(width 0.18288)
		(layer "In6.Cu")
		(net "M_C_CPU0_SB_DQ<14>")
	)
	(segment
		(start 317.557404 -224.846134)
		(end 314.369196 -221.657926)
		(width 0.18288)
		(layer "In6.Cu")
		(net "M_C_CPU0_SB_DQ<14>")
	)
	(segment
		(start 317.557404 -227.42144)
		(end 317.557404 -224.846134)
		(width 0.18288)
		(layer "In6.Cu")
		(net "M_C_CPU0_SB_DQ<14>")
	)
	(segment
		(start 301.291244 -218.398852)
		(end 301.291244 -218.809062)
		(width 0.18288)
		(layer "In6.Cu")
		(net "M_C_CPU0_SB_DQ<14>")
	)
	(segment
		(start 302.165004 -218.991942)
		(end 301.982124 -218.809062)
		(width 0.18288)
		(layer "In6.Cu")
		(net "M_C_CPU0_SB_DQ<14>")
	)
	(segment
		(start 294.590724 -217.291666)
		(end 293.545514 -218.336876)
		(width 0.18288)
		(layer "In6.Cu")
		(net "M_C_CPU0_SB_DQ<14>")
	)
	(segment
		(start 334.771238 -235.792772)
		(end 334.771238 -235.769912)
		(width 0.088646)
		(layer "In6.Cu")
		(net "M_C_CPU0_SB_DQ<14>")
	)
	(segment
		(start 331.664056 -234.580684)
		(end 331.382878 -233.901488)
		(width 0.088646)
		(layer "In6.Cu")
		(net "M_C_CPU0_SB_DQ<14>")
	)
	(segment
		(start 285.746698 -216.567512)
		(end 285.563818 -216.750392)
		(width 0.18288)
		(layer "In6.Cu")
		(net "M_C_CPU0_SB_DQ<14>")
	)
	(segment
		(start 285.929578 -216.101676)
		(end 285.746698 -216.284556)
		(width 0.18288)
		(layer "In6.Cu")
		(net "M_C_CPU0_SB_DQ<14>")
	)
	(segment
		(start 293.545514 -218.336876)
		(end 291.01923 -218.336876)
		(width 0.18288)
		(layer "In6.Cu")
		(net "M_C_CPU0_SB_DQ<14>")
	)
	(segment
		(start 288.312098 -216.750392)
		(end 286.620458 -216.750392)
		(width 0.18288)
		(layer "In6.Cu")
		(net "M_C_CPU0_SB_DQ<14>")
	)
	(segment
		(start 332.200504 -235.218986)
		(end 331.664056 -234.682538)
		(width 0.088646)
		(layer "In6.Cu")
		(net "M_C_CPU0_SB_DQ<14>")
	)
	(segment
		(start 303.105312 -218.991942)
		(end 302.165004 -218.991942)
		(width 0.18288)
		(layer "In6.Cu")
		(net "M_C_CPU0_SB_DQ<14>")
	)
	(segment
		(start 331.382878 -233.901488)
		(end 330.878434 -233.397044)
		(width 0.088646)
		(layer "In6.Cu")
		(net "M_C_CPU0_SB_DQ<14>")
	)
	(segment
		(start 311.224168 -220.44914)
		(end 310.289448 -219.51442)
		(width 0.18288)
		(layer "In6.Cu")
		(net "M_C_CPU0_SB_DQ<14>")
	)
	(segment
		(start 340.986364 -236.099604)
		(end 340.971632 -236.10824)
		(width 0.088646)
		(layer "In6.Cu")
		(net "M_C_CPU0_SB_DQ<14>")
	)
	(segment
		(start 337.227164 -236.099604)
		(end 337.212432 -236.10824)
		(width 0.088646)
		(layer "In6.Cu")
		(net "M_C_CPU0_SB_DQ<14>")
	)
	(segment
		(start 303.761648 -218.335606)
		(end 303.105312 -218.991942)
		(width 0.18288)
		(layer "In6.Cu")
		(net "M_C_CPU0_SB_DQ<14>")
	)
	(segment
		(start 286.437578 -216.284556)
		(end 286.254698 -216.101676)
		(width 0.18288)
		(layer "In6.Cu")
		(net "M_C_CPU0_SB_DQ<14>")
	)
	(segment
		(start 314.369196 -221.657926)
		(end 313.067446 -221.657926)
		(width 0.18288)
		(layer "In6.Cu")
		(net "M_C_CPU0_SB_DQ<14>")
	)
	(segment
		(start 299.909484 -218.398852)
		(end 299.909484 -218.809062)
		(width 0.18288)
		(layer "In6.Cu")
		(net "M_C_CPU0_SB_DQ<14>")
	)
	(segment
		(start 288.954972 -217.393266)
		(end 288.312098 -216.750392)
		(width 0.18288)
		(layer "In6.Cu")
		(net "M_C_CPU0_SB_DQ<14>")
	)
	(arc
		(start 334.488536 -235.294424)
		(mid 334.211064 -235.218706)
		(end 333.932276 -235.289344)
		(width 0.088646)
		(layer "In6.Cu")
		(net "M_C_CPU0_SB_DQ<14>")
	)
	(arc
		(start 340.597236 -236.10824)
		(mid 340.323007 -236.032315)
		(end 340.046564 -236.099604)
		(width 0.088646)
		(layer "In6.Cu")
		(net "M_C_CPU0_SB_DQ<14>")
	)
	(arc
		(start 345.01328 -236.597952)
		(mid 344.571841 -236.302992)
		(end 344.051128 -236.199426)
		(width 0.088646)
		(layer "In6.Cu")
		(net "M_C_CPU0_SB_DQ<14>")
	)
	(arc
		(start 338.152232 -236.10824)
		(mid 337.965034 -236.158383)
		(end 337.777836 -236.10824)
		(width 0.088646)
		(layer "In6.Cu")
		(net "M_C_CPU0_SB_DQ<14>")
	)
	(arc
		(start 332.608682 -235.294678)
		(mid 332.472313 -235.238236)
		(end 332.32598 -235.218986)
		(width 0.088646)
		(layer "In6.Cu")
		(net "M_C_CPU0_SB_DQ<14>")
	)
	(arc
		(start 340.971632 -236.10824)
		(mid 340.784434 -236.158383)
		(end 340.597236 -236.10824)
		(width 0.088646)
		(layer "In6.Cu")
		(net "M_C_CPU0_SB_DQ<14>")
	)
	(arc
		(start 336.272632 -236.10824)
		(mid 336.085434 -236.158383)
		(end 335.898236 -236.10824)
		(width 0.088646)
		(layer "In6.Cu")
		(net "M_C_CPU0_SB_DQ<14>")
	)
	(arc
		(start 337.777836 -236.10824)
		(mid 337.503607 -236.032315)
		(end 337.227164 -236.099604)
		(width 0.088646)
		(layer "In6.Cu")
		(net "M_C_CPU0_SB_DQ<14>")
	)
	(arc
		(start 334.958436 -236.108494)
		(mid 334.823503 -235.97514)
		(end 334.771238 -235.792772)
		(width 0.088646)
		(layer "In6.Cu")
		(net "M_C_CPU0_SB_DQ<14>")
	)
	(arc
		(start 336.838036 -236.10824)
		(mid 336.555334 -236.032498)
		(end 336.272632 -236.10824)
		(width 0.088646)
		(layer "In6.Cu")
		(net "M_C_CPU0_SB_DQ<14>")
	)
	(arc
		(start 341.911432 -236.10824)
		(mid 341.724234 -236.158383)
		(end 341.537036 -236.10824)
		(width 0.088646)
		(layer "In6.Cu")
		(net "M_C_CPU0_SB_DQ<14>")
	)
	(arc
		(start 335.898236 -236.10824)
		(mid 335.623409 -236.032429)
		(end 335.346548 -236.100366)
		(width 0.088646)
		(layer "In6.Cu")
		(net "M_C_CPU0_SB_DQ<14>")
	)
	(arc
		(start 337.212432 -236.10824)
		(mid 337.025234 -236.158383)
		(end 336.838036 -236.10824)
		(width 0.088646)
		(layer "In6.Cu")
		(net "M_C_CPU0_SB_DQ<14>")
	)
	(arc
		(start 342.476836 -236.10824)
		(mid 342.194134 -236.032498)
		(end 341.911432 -236.10824)
		(width 0.088646)
		(layer "In6.Cu")
		(net "M_C_CPU0_SB_DQ<14>")
	)
	(arc
		(start 333.538576 -235.288582)
		(mid 333.260144 -235.218736)
		(end 332.983332 -235.294678)
		(width 0.088646)
		(layer "In6.Cu")
		(net "M_C_CPU0_SB_DQ<14>")
	)
	(arc
		(start 332.983332 -235.294678)
		(mid 332.800827 -235.344916)
		(end 332.617064 -235.299504)
		(width 0.088646)
		(layer "In6.Cu")
		(net "M_C_CPU0_SB_DQ<14>")
	)
	(arc
		(start 344.051128 -236.199426)
		(mid 343.559347 -236.193075)
		(end 343.067894 -236.174026)
		(width 0.088646)
		(layer "In6.Cu")
		(net "M_C_CPU0_SB_DQ<14>")
	)
	(arc
		(start 339.657436 -236.10824)
		(mid 339.380623 -236.032404)
		(end 339.102192 -236.102144)
		(width 0.088646)
		(layer "In6.Cu")
		(net "M_C_CPU0_SB_DQ<14>")
	)
	(arc
		(start 341.537036 -236.10824)
		(mid 341.262807 -236.032315)
		(end 340.986364 -236.099604)
		(width 0.088646)
		(layer "In6.Cu")
		(net "M_C_CPU0_SB_DQ<14>")
	)
	(arc
		(start 340.031832 -236.10824)
		(mid 339.844634 -236.158383)
		(end 339.657436 -236.10824)
		(width 0.088646)
		(layer "In6.Cu")
		(net "M_C_CPU0_SB_DQ<14>")
	)
	(arc
		(start 339.091778 -236.10824)
		(mid 338.90458 -236.158383)
		(end 338.717382 -236.10824)
		(width 0.088646)
		(layer "In6.Cu")
		(net "M_C_CPU0_SB_DQ<14>")
	)
	(arc
		(start 333.923386 -235.294678)
		(mid 333.736188 -235.344821)
		(end 333.54899 -235.294678)
		(width 0.088646)
		(layer "In6.Cu")
		(net "M_C_CPU0_SB_DQ<14>")
	)
	(arc
		(start 334.771238 -235.769912)
		(mid 334.692019 -235.495227)
		(end 334.488536 -235.294424)
		(width 0.088646)
		(layer "In6.Cu")
		(net "M_C_CPU0_SB_DQ<14>")
	)
	(arc
		(start 343.067894 -236.174026)
		(mid 342.765471 -236.203021)
		(end 342.476836 -236.10824)
		(width 0.088646)
		(layer "In6.Cu")
		(net "M_C_CPU0_SB_DQ<14>")
	)
	(arc
		(start 338.717382 -236.10824)
		(mid 338.440823 -236.032531)
		(end 338.162646 -236.102144)
		(width 0.088646)
		(layer "In6.Cu")
		(net "M_C_CPU0_SB_DQ<14>")
	)
	(arc
		(start 335.332832 -236.108494)
		(mid 335.145634 -236.158637)
		(end 334.958436 -236.108494)
		(width 0.088646)
		(layer "In6.Cu")
		(net "M_C_CPU0_SB_DQ<14>")
	)
	(segment
		(start 276.647656 -214.74176)
		(end 276.469094 -214.74176)
		(width 0.20066)
		(layer "F.Cu")
		(net "M_C_CPU0_SB_DQ<13>")
	)
	(segment
		(start 273.37258 -215.223598)
		(end 273.218148 -215.37803)
		(width 0.20066)
		(layer "F.Cu")
		(net "M_C_CPU0_SB_DQ<13>")
	)
	(segment
		(start 274.143978 -214.73287)
		(end 273.53514 -214.73287)
		(width 0.20066)
		(layer "F.Cu")
		(net "M_C_CPU0_SB_DQ<13>")
	)
	(segment
		(start 278.711914 -215.166702)
		(end 277.072598 -215.166702)
		(width 0.20066)
		(layer "F.Cu")
		(net "M_C_CPU0_SB_DQ<13>")
	)
	(segment
		(start 272.502376 -215.166702)
		(end 271.168114 -215.166702)
		(width 0.20066)
		(layer "F.Cu")
		(net "M_C_CPU0_SB_DQ<13>")
	)
	(segment
		(start 272.713704 -215.37803)
		(end 272.502376 -215.166702)
		(width 0.20066)
		(layer "F.Cu")
		(net "M_C_CPU0_SB_DQ<13>")
	)
	(segment
		(start 279.816814 -215.166702)
		(end 278.711914 -215.166702)
		(width 0.20066)
		(layer "F.Cu")
		(net "M_C_CPU0_SB_DQ<13>")
	)
	(segment
		(start 343.60358 -236.319822)
		(end 343.603834 -236.319568)
		(width 0.20066)
		(layer "F.Cu")
		(net "M_C_CPU0_SB_DQ<13>")
	)
	(segment
		(start 273.53514 -214.73287)
		(end 273.37258 -214.89543)
		(width 0.20066)
		(layer "F.Cu")
		(net "M_C_CPU0_SB_DQ<13>")
	)
	(segment
		(start 276.469094 -214.74176)
		(end 276.138386 -214.74176)
		(width 0.101854)
		(layer "F.Cu")
		(net "M_C_CPU0_SB_DQ<13>")
	)
	(segment
		(start 343.603834 -236.319568)
		(end 343.603834 -235.783882)
		(width 0.20066)
		(layer "F.Cu")
		(net "M_C_CPU0_SB_DQ<13>")
	)
	(segment
		(start 273.218148 -215.37803)
		(end 272.713704 -215.37803)
		(width 0.20066)
		(layer "F.Cu")
		(net "M_C_CPU0_SB_DQ<13>")
	)
	(segment
		(start 276.138386 -214.74176)
		(end 274.152868 -214.74176)
		(width 0.1016)
		(layer "F.Cu")
		(net "M_C_CPU0_SB_DQ<13>")
	)
	(segment
		(start 277.072598 -215.166702)
		(end 276.647656 -214.74176)
		(width 0.20066)
		(layer "F.Cu")
		(net "M_C_CPU0_SB_DQ<13>")
	)
	(segment
		(start 273.37258 -214.89543)
		(end 273.37258 -215.223598)
		(width 0.20066)
		(layer "F.Cu")
		(net "M_C_CPU0_SB_DQ<13>")
	)
	(segment
		(start 274.152868 -214.74176)
		(end 274.143978 -214.73287)
		(width 0.1016)
		(layer "F.Cu")
		(net "M_C_CPU0_SB_DQ<13>")
	)
	(segment
		(start 307.993034 -217.220038)
		(end 307.154834 -217.220038)
		(width 0.18288)
		(layer "In6.Cu")
		(net "M_C_CPU0_SB_DQ<13>")
	)
	(segment
		(start 334.862678 -234.645962)
		(end 334.851756 -234.639612)
		(width 0.088646)
		(layer "In6.Cu")
		(net "M_C_CPU0_SB_DQ<13>")
	)
	(segment
		(start 336.287364 -235.46816)
		(end 336.272632 -235.459524)
		(width 0.088646)
		(layer "In6.Cu")
		(net "M_C_CPU0_SB_DQ<13>")
	)
	(segment
		(start 288.696908 -216.394538)
		(end 287.89376 -215.59139)
		(width 0.18288)
		(layer "In6.Cu")
		(net "M_C_CPU0_SB_DQ<13>")
	)
	(segment
		(start 330.892404 -232.899204)
		(end 330.572364 -232.899204)
		(width 0.088646)
		(layer "In6.Cu")
		(net "M_C_CPU0_SB_DQ<13>")
	)
	(segment
		(start 333.923132 -234.645962)
		(end 333.91475 -234.641136)
		(width 0.088646)
		(layer "In6.Cu")
		(net "M_C_CPU0_SB_DQ<13>")
	)
	(segment
		(start 294.729662 -216.441782)
		(end 293.88308 -217.288364)
		(width 0.18288)
		(layer "In6.Cu")
		(net "M_C_CPU0_SB_DQ<13>")
	)
	(segment
		(start 290.679378 -217.288364)
		(end 289.785552 -216.394538)
		(width 0.18288)
		(layer "In6.Cu")
		(net "M_C_CPU0_SB_DQ<13>")
	)
	(segment
		(start 303.656492 -217.770456)
		(end 303.17694 -217.290904)
		(width 0.18288)
		(layer "In6.Cu")
		(net "M_C_CPU0_SB_DQ<13>")
	)
	(segment
		(start 310.506618 -218.968574)
		(end 309.74157 -218.968574)
		(width 0.18288)
		(layer "In6.Cu")
		(net "M_C_CPU0_SB_DQ<13>")
	)
	(segment
		(start 340.046564 -235.46816)
		(end 340.031832 -235.459524)
		(width 0.088646)
		(layer "In6.Cu")
		(net "M_C_CPU0_SB_DQ<13>")
	)
	(segment
		(start 323.811138 -232.899204)
		(end 318.055244 -227.14331)
		(width 0.18288)
		(layer "In6.Cu")
		(net "M_C_CPU0_SB_DQ<13>")
	)
	(segment
		(start 318.055244 -227.14331)
		(end 318.055244 -224.436686)
		(width 0.18288)
		(layer "In6.Cu")
		(net "M_C_CPU0_SB_DQ<13>")
	)
	(segment
		(start 342.865964 -235.46816)
		(end 342.851232 -235.459524)
		(width 0.088646)
		(layer "In6.Cu")
		(net "M_C_CPU0_SB_DQ<13>")
	)
	(segment
		(start 289.785552 -216.394538)
		(end 288.696908 -216.394538)
		(width 0.18288)
		(layer "In6.Cu")
		(net "M_C_CPU0_SB_DQ<13>")
	)
	(segment
		(start 287.89376 -215.59139)
		(end 280.241502 -215.59139)
		(width 0.18288)
		(layer "In6.Cu")
		(net "M_C_CPU0_SB_DQ<13>")
	)
	(segment
		(start 318.055244 -224.436686)
		(end 314.095638 -220.47708)
		(width 0.18288)
		(layer "In6.Cu")
		(net "M_C_CPU0_SB_DQ<13>")
	)
	(segment
		(start 334.876902 -234.65409)
		(end 334.862678 -234.645962)
		(width 0.088646)
		(layer "In6.Cu")
		(net "M_C_CPU0_SB_DQ<13>")
	)
	(segment
		(start 333.54899 -234.645962)
		(end 333.538576 -234.652058)
		(width 0.088646)
		(layer "In6.Cu")
		(net "M_C_CPU0_SB_DQ<13>")
	)
	(segment
		(start 341.926164 -235.46816)
		(end 341.911432 -235.459524)
		(width 0.088646)
		(layer "In6.Cu")
		(net "M_C_CPU0_SB_DQ<13>")
	)
	(segment
		(start 330.572364 -232.899204)
		(end 323.811138 -232.899204)
		(width 0.18288)
		(layer "In6.Cu")
		(net "M_C_CPU0_SB_DQ<13>")
	)
	(segment
		(start 280.241502 -215.59139)
		(end 279.816814 -215.166702)
		(width 0.18288)
		(layer "In6.Cu")
		(net "M_C_CPU0_SB_DQ<13>")
	)
	(segment
		(start 335.909158 -235.453428)
		(end 335.898236 -235.459778)
		(width 0.088646)
		(layer "In6.Cu")
		(net "M_C_CPU0_SB_DQ<13>")
	)
	(segment
		(start 331.926184 -234.5563)
		(end 331.832966 -234.463082)
		(width 0.088646)
		(layer "In6.Cu")
		(net "M_C_CPU0_SB_DQ<13>")
	)
	(segment
		(start 338.717382 -235.459524)
		(end 338.706968 -235.46562)
		(width 0.088646)
		(layer "In6.Cu")
		(net "M_C_CPU0_SB_DQ<13>")
	)
	(segment
		(start 311.480454 -219.94241)
		(end 310.506618 -218.968574)
		(width 0.18288)
		(layer "In6.Cu")
		(net "M_C_CPU0_SB_DQ<13>")
	)
	(segment
		(start 297.183048 -216.441782)
		(end 294.729662 -216.441782)
		(width 0.18288)
		(layer "In6.Cu")
		(net "M_C_CPU0_SB_DQ<13>")
	)
	(segment
		(start 309.74157 -218.968574)
		(end 307.993034 -217.220038)
		(width 0.18288)
		(layer "In6.Cu")
		(net "M_C_CPU0_SB_DQ<13>")
	)
	(segment
		(start 314.095638 -220.47708)
		(end 312.630058 -220.47708)
		(width 0.18288)
		(layer "In6.Cu")
		(net "M_C_CPU0_SB_DQ<13>")
	)
	(segment
		(start 312.630058 -220.47708)
		(end 312.095388 -219.94241)
		(width 0.18288)
		(layer "In6.Cu")
		(net "M_C_CPU0_SB_DQ<13>")
	)
	(segment
		(start 307.154834 -217.220038)
		(end 306.604416 -217.770456)
		(width 0.18288)
		(layer "In6.Cu")
		(net "M_C_CPU0_SB_DQ<13>")
	)
	(segment
		(start 332.617064 -234.641136)
		(end 332.590648 -234.656376)
		(width 0.088646)
		(layer "In6.Cu")
		(net "M_C_CPU0_SB_DQ<13>")
	)
	(segment
		(start 339.102192 -235.46562)
		(end 339.091778 -235.459524)
		(width 0.088646)
		(layer "In6.Cu")
		(net "M_C_CPU0_SB_DQ<13>")
	)
	(segment
		(start 331.707998 -234.16133)
		(end 331.707998 -233.714798)
		(width 0.088646)
		(layer "In6.Cu")
		(net "M_C_CPU0_SB_DQ<13>")
	)
	(segment
		(start 337.227164 -235.46816)
		(end 337.212432 -235.459524)
		(width 0.088646)
		(layer "In6.Cu")
		(net "M_C_CPU0_SB_DQ<13>")
	)
	(segment
		(start 306.604416 -217.770456)
		(end 303.656492 -217.770456)
		(width 0.18288)
		(layer "In6.Cu")
		(net "M_C_CPU0_SB_DQ<13>")
	)
	(segment
		(start 335.332832 -235.459778)
		(end 335.32064 -235.452666)
		(width 0.088646)
		(layer "In6.Cu")
		(net "M_C_CPU0_SB_DQ<13>")
	)
	(segment
		(start 312.095388 -219.94241)
		(end 311.480454 -219.94241)
		(width 0.18288)
		(layer "In6.Cu")
		(net "M_C_CPU0_SB_DQ<13>")
	)
	(segment
		(start 340.986364 -235.46816)
		(end 340.971632 -235.459524)
		(width 0.088646)
		(layer "In6.Cu")
		(net "M_C_CPU0_SB_DQ<13>")
	)
	(segment
		(start 293.88308 -217.288364)
		(end 290.679378 -217.288364)
		(width 0.18288)
		(layer "In6.Cu")
		(net "M_C_CPU0_SB_DQ<13>")
	)
	(segment
		(start 298.03217 -217.290904)
		(end 297.183048 -216.441782)
		(width 0.18288)
		(layer "In6.Cu")
		(net "M_C_CPU0_SB_DQ<13>")
	)
	(segment
		(start 331.707998 -233.714798)
		(end 330.892404 -232.899204)
		(width 0.088646)
		(layer "In6.Cu")
		(net "M_C_CPU0_SB_DQ<13>")
	)
	(segment
		(start 303.17694 -217.290904)
		(end 298.03217 -217.290904)
		(width 0.18288)
		(layer "In6.Cu")
		(net "M_C_CPU0_SB_DQ<13>")
	)
	(segment
		(start 331.832966 -234.463082)
		(end 331.707998 -234.16133)
		(width 0.088646)
		(layer "In6.Cu")
		(net "M_C_CPU0_SB_DQ<13>")
	)
	(segment
		(start 334.488282 -234.645708)
		(end 334.479392 -234.651042)
		(width 0.088646)
		(layer "In6.Cu")
		(net "M_C_CPU0_SB_DQ<13>")
	)
	(arc
		(start 333.538576 -234.652058)
		(mid 333.260144 -234.721904)
		(end 332.983332 -234.645962)
		(width 0.088646)
		(layer "In6.Cu")
		(net "M_C_CPU0_SB_DQ<13>")
	)
	(arc
		(start 342.476836 -235.459524)
		(mid 342.202637 -235.535359)
		(end 341.926164 -235.46816)
		(width 0.088646)
		(layer "In6.Cu")
		(net "M_C_CPU0_SB_DQ<13>")
	)
	(arc
		(start 338.706968 -235.46562)
		(mid 338.42879 -235.535343)
		(end 338.152232 -235.459524)
		(width 0.088646)
		(layer "In6.Cu")
		(net "M_C_CPU0_SB_DQ<13>")
	)
	(arc
		(start 334.851756 -234.639612)
		(mid 334.669226 -234.595588)
		(end 334.488282 -234.645708)
		(width 0.088646)
		(layer "In6.Cu")
		(net "M_C_CPU0_SB_DQ<13>")
	)
	(arc
		(start 332.983332 -234.645962)
		(mid 332.800827 -234.595724)
		(end 332.617064 -234.641136)
		(width 0.088646)
		(layer "In6.Cu")
		(net "M_C_CPU0_SB_DQ<13>")
	)
	(arc
		(start 337.212432 -235.459524)
		(mid 337.025234 -235.409381)
		(end 336.838036 -235.459524)
		(width 0.088646)
		(layer "In6.Cu")
		(net "M_C_CPU0_SB_DQ<13>")
	)
	(arc
		(start 340.031832 -235.459524)
		(mid 339.844634 -235.409381)
		(end 339.657436 -235.459524)
		(width 0.088646)
		(layer "In6.Cu")
		(net "M_C_CPU0_SB_DQ<13>")
	)
	(arc
		(start 334.479392 -234.651042)
		(mid 334.200604 -234.721605)
		(end 333.923132 -234.645962)
		(width 0.088646)
		(layer "In6.Cu")
		(net "M_C_CPU0_SB_DQ<13>")
	)
	(arc
		(start 332.590648 -234.656376)
		(mid 332.241957 -234.715659)
		(end 331.926184 -234.5563)
		(width 0.088646)
		(layer "In6.Cu")
		(net "M_C_CPU0_SB_DQ<13>")
	)
	(arc
		(start 339.091778 -235.459524)
		(mid 338.90458 -235.409381)
		(end 338.717382 -235.459524)
		(width 0.088646)
		(layer "In6.Cu")
		(net "M_C_CPU0_SB_DQ<13>")
	)
	(arc
		(start 338.152232 -235.459524)
		(mid 337.965034 -235.409381)
		(end 337.777836 -235.459524)
		(width 0.088646)
		(layer "In6.Cu")
		(net "M_C_CPU0_SB_DQ<13>")
	)
	(arc
		(start 336.838036 -235.459524)
		(mid 336.563837 -235.535359)
		(end 336.287364 -235.46816)
		(width 0.088646)
		(layer "In6.Cu")
		(net "M_C_CPU0_SB_DQ<13>")
	)
	(arc
		(start 340.597236 -235.459524)
		(mid 340.323037 -235.535359)
		(end 340.046564 -235.46816)
		(width 0.088646)
		(layer "In6.Cu")
		(net "M_C_CPU0_SB_DQ<13>")
	)
	(arc
		(start 333.91475 -234.641136)
		(mid 333.731242 -234.595858)
		(end 333.54899 -234.645962)
		(width 0.088646)
		(layer "In6.Cu")
		(net "M_C_CPU0_SB_DQ<13>")
	)
	(arc
		(start 341.911432 -235.459524)
		(mid 341.724234 -235.409381)
		(end 341.537036 -235.459524)
		(width 0.088646)
		(layer "In6.Cu")
		(net "M_C_CPU0_SB_DQ<13>")
	)
	(arc
		(start 341.537036 -235.459524)
		(mid 341.262837 -235.535359)
		(end 340.986364 -235.46816)
		(width 0.088646)
		(layer "In6.Cu")
		(net "M_C_CPU0_SB_DQ<13>")
	)
	(arc
		(start 336.272632 -235.459524)
		(mid 336.091688 -235.409433)
		(end 335.909158 -235.453428)
		(width 0.088646)
		(layer "In6.Cu")
		(net "M_C_CPU0_SB_DQ<13>")
	)
	(arc
		(start 335.32064 -235.452666)
		(mid 335.12235 -235.246707)
		(end 335.05013 -234.970066)
		(width 0.088646)
		(layer "In6.Cu")
		(net "M_C_CPU0_SB_DQ<13>")
	)
	(arc
		(start 335.898236 -235.459778)
		(mid 335.615534 -235.535554)
		(end 335.332832 -235.459778)
		(width 0.088646)
		(layer "In6.Cu")
		(net "M_C_CPU0_SB_DQ<13>")
	)
	(arc
		(start 343.603834 -235.783882)
		(mid 343.358692 -235.613501)
		(end 343.07145 -235.532168)
		(width 0.088646)
		(layer "In6.Cu")
		(net "M_C_CPU0_SB_DQ<13>")
	)
	(arc
		(start 342.851232 -235.459524)
		(mid 342.664034 -235.409381)
		(end 342.476836 -235.459524)
		(width 0.088646)
		(layer "In6.Cu")
		(net "M_C_CPU0_SB_DQ<13>")
	)
	(arc
		(start 339.657436 -235.459524)
		(mid 339.380623 -235.535394)
		(end 339.102192 -235.46562)
		(width 0.088646)
		(layer "In6.Cu")
		(net "M_C_CPU0_SB_DQ<13>")
	)
	(arc
		(start 343.07145 -235.532168)
		(mid 342.965623 -235.510055)
		(end 342.865964 -235.46816)
		(width 0.088646)
		(layer "In6.Cu")
		(net "M_C_CPU0_SB_DQ<13>")
	)
	(arc
		(start 335.05013 -234.970066)
		(mid 335.003991 -234.789881)
		(end 334.876902 -234.65409)
		(width 0.088646)
		(layer "In6.Cu")
		(net "M_C_CPU0_SB_DQ<13>")
	)
	(arc
		(start 337.777836 -235.459524)
		(mid 337.503637 -235.535359)
		(end 337.227164 -235.46816)
		(width 0.088646)
		(layer "In6.Cu")
		(net "M_C_CPU0_SB_DQ<13>")
	)
	(arc
		(start 340.971632 -235.459524)
		(mid 340.784434 -235.409381)
		(end 340.597236 -235.459524)
		(width 0.088646)
		(layer "In6.Cu")
		(net "M_C_CPU0_SB_DQ<13>")
	)
	(segment
		(start 272.741136 -217.105484)
		(end 272.502376 -216.866724)
		(width 0.20066)
		(layer "F.Cu")
		(net "M_C_CPU0_SB_DQ<12>")
	)
	(segment
		(start 273.58213 -216.433654)
		(end 273.37258 -216.643204)
		(width 0.20066)
		(layer "F.Cu")
		(net "M_C_CPU0_SB_DQ<12>")
	)
	(segment
		(start 273.19986 -217.105484)
		(end 272.741136 -217.105484)
		(width 0.20066)
		(layer "F.Cu")
		(net "M_C_CPU0_SB_DQ<12>")
	)
	(segment
		(start 274.152106 -216.441782)
		(end 274.143978 -216.433654)
		(width 0.101854)
		(layer "F.Cu")
		(net "M_C_CPU0_SB_DQ<12>")
	)
	(segment
		(start 274.143978 -216.433654)
		(end 273.58213 -216.433654)
		(width 0.20066)
		(layer "F.Cu")
		(net "M_C_CPU0_SB_DQ<12>")
	)
	(segment
		(start 343.13368 -237.133638)
		(end 343.13368 -236.597952)
		(width 0.20066)
		(layer "F.Cu")
		(net "M_C_CPU0_SB_DQ<12>")
	)
	(segment
		(start 274.40001 -216.441782)
		(end 274.152106 -216.441782)
		(width 0.101854)
		(layer "F.Cu")
		(net "M_C_CPU0_SB_DQ<12>")
	)
	(segment
		(start 343.133934 -237.133892)
		(end 343.13368 -237.133638)
		(width 0.20066)
		(layer "F.Cu")
		(net "M_C_CPU0_SB_DQ<12>")
	)
	(segment
		(start 273.37258 -216.932764)
		(end 273.19986 -217.105484)
		(width 0.20066)
		(layer "F.Cu")
		(net "M_C_CPU0_SB_DQ<12>")
	)
	(segment
		(start 276.469094 -216.441782)
		(end 274.40001 -216.441782)
		(width 0.1016)
		(layer "F.Cu")
		(net "M_C_CPU0_SB_DQ<12>")
	)
	(segment
		(start 277.342854 -216.866724)
		(end 276.917912 -216.441782)
		(width 0.20066)
		(layer "F.Cu")
		(net "M_C_CPU0_SB_DQ<12>")
	)
	(segment
		(start 278.711914 -216.866724)
		(end 277.342854 -216.866724)
		(width 0.20066)
		(layer "F.Cu")
		(net "M_C_CPU0_SB_DQ<12>")
	)
	(segment
		(start 273.37258 -216.643204)
		(end 273.37258 -216.932764)
		(width 0.20066)
		(layer "F.Cu")
		(net "M_C_CPU0_SB_DQ<12>")
	)
	(segment
		(start 276.917912 -216.441782)
		(end 276.469094 -216.441782)
		(width 0.20066)
		(layer "F.Cu")
		(net "M_C_CPU0_SB_DQ<12>")
	)
	(segment
		(start 279.816814 -216.866724)
		(end 278.711914 -216.866724)
		(width 0.20066)
		(layer "F.Cu")
		(net "M_C_CPU0_SB_DQ<12>")
	)
	(segment
		(start 272.502376 -216.866724)
		(end 271.168114 -216.866724)
		(width 0.20066)
		(layer "F.Cu")
		(net "M_C_CPU0_SB_DQ<12>")
	)
	(segment
		(start 305.521614 -219.121736)
		(end 305.521614 -219.567506)
		(width 0.18288)
		(layer "In6.Cu")
		(net "M_C_CPU0_SB_DQ<12>")
	)
	(segment
		(start 305.521614 -219.567506)
		(end 305.338734 -219.750386)
		(width 0.18288)
		(layer "In6.Cu")
		(net "M_C_CPU0_SB_DQ<12>")
	)
	(segment
		(start 342.006936 -236.273594)
		(end 341.996522 -236.27969)
		(width 0.088646)
		(layer "In6.Cu")
		(net "M_C_CPU0_SB_DQ<12>")
	)
	(segment
		(start 288.583624 -218.000834)
		(end 287.874202 -217.291412)
		(width 0.18288)
		(layer "In6.Cu")
		(net "M_C_CPU0_SB_DQ<12>")
	)
	(segment
		(start 298.262294 -219.841064)
		(end 296.563034 -218.141804)
		(width 0.18288)
		(layer "In6.Cu")
		(net "M_C_CPU0_SB_DQ<12>")
	)
	(segment
		(start 330.572364 -233.894884)
		(end 323.254624 -233.894884)
		(width 0.18288)
		(layer "In6.Cu")
		(net "M_C_CPU0_SB_DQ<12>")
	)
	(segment
		(start 312.276236 -222.222568)
		(end 310.758078 -220.70441)
		(width 0.18288)
		(layer "In6.Cu")
		(net "M_C_CPU0_SB_DQ<12>")
	)
	(segment
		(start 332.12151 -235.409232)
		(end 331.47381 -234.761532)
		(width 0.088646)
		(layer "In6.Cu")
		(net "M_C_CPU0_SB_DQ<12>")
	)
	(segment
		(start 331.068426 -233.894884)
		(end 330.572364 -233.894884)
		(width 0.088646)
		(layer "In6.Cu")
		(net "M_C_CPU0_SB_DQ<12>")
	)
	(segment
		(start 294.647366 -218.141804)
		(end 293.929054 -218.860116)
		(width 0.18288)
		(layer "In6.Cu")
		(net "M_C_CPU0_SB_DQ<12>")
	)
	(segment
		(start 303.054766 -219.841064)
		(end 298.262294 -219.841064)
		(width 0.18288)
		(layer "In6.Cu")
		(net "M_C_CPU0_SB_DQ<12>")
	)
	(segment
		(start 308.012338 -218.938856)
		(end 305.704494 -218.938856)
		(width 0.18288)
		(layer "In6.Cu")
		(net "M_C_CPU0_SB_DQ<12>")
	)
	(segment
		(start 303.956974 -218.938856)
		(end 303.054766 -219.841064)
		(width 0.18288)
		(layer "In6.Cu")
		(net "M_C_CPU0_SB_DQ<12>")
	)
	(segment
		(start 289.931602 -218.000834)
		(end 288.583624 -218.000834)
		(width 0.18288)
		(layer "In6.Cu")
		(net "M_C_CPU0_SB_DQ<12>")
	)
	(segment
		(start 331.47381 -234.761532)
		(end 331.47381 -234.634024)
		(width 0.088646)
		(layer "In6.Cu")
		(net "M_C_CPU0_SB_DQ<12>")
	)
	(segment
		(start 323.254624 -233.894884)
		(end 317.048896 -227.689156)
		(width 0.18288)
		(layer "In6.Cu")
		(net "M_C_CPU0_SB_DQ<12>")
	)
	(segment
		(start 331.237844 -234.064302)
		(end 331.068426 -233.894884)
		(width 0.088646)
		(layer "In6.Cu")
		(net "M_C_CPU0_SB_DQ<12>")
	)
	(segment
		(start 296.563034 -218.141804)
		(end 294.647366 -218.141804)
		(width 0.18288)
		(layer "In6.Cu")
		(net "M_C_CPU0_SB_DQ<12>")
	)
	(segment
		(start 340.127082 -236.273594)
		(end 340.11235 -236.28223)
		(width 0.088646)
		(layer "In6.Cu")
		(net "M_C_CPU0_SB_DQ<12>")
	)
	(segment
		(start 305.338734 -219.750386)
		(end 305.013614 -219.750386)
		(width 0.18288)
		(layer "In6.Cu")
		(net "M_C_CPU0_SB_DQ<12>")
	)
	(segment
		(start 332.32598 -235.409232)
		(end 332.12151 -235.409232)
		(width 0.088646)
		(layer "In6.Cu")
		(net "M_C_CPU0_SB_DQ<12>")
	)
	(segment
		(start 331.47381 -234.634024)
		(end 331.237844 -234.064302)
		(width 0.088646)
		(layer "In6.Cu")
		(net "M_C_CPU0_SB_DQ<12>")
	)
	(segment
		(start 304.830734 -219.121736)
		(end 304.647854 -218.938856)
		(width 0.18288)
		(layer "In6.Cu")
		(net "M_C_CPU0_SB_DQ<12>")
	)
	(segment
		(start 334.393032 -235.459778)
		(end 334.38465 -235.454952)
		(width 0.088646)
		(layer "In6.Cu")
		(net "M_C_CPU0_SB_DQ<12>")
	)
	(segment
		(start 305.013614 -219.750386)
		(end 304.830734 -219.567506)
		(width 0.18288)
		(layer "In6.Cu")
		(net "M_C_CPU0_SB_DQ<12>")
	)
	(segment
		(start 287.86328 -217.291412)
		(end 287.862772 -217.290904)
		(width 0.18288)
		(layer "In6.Cu")
		(net "M_C_CPU0_SB_DQ<12>")
	)
	(segment
		(start 305.704494 -218.938856)
		(end 305.521614 -219.121736)
		(width 0.18288)
		(layer "In6.Cu")
		(net "M_C_CPU0_SB_DQ<12>")
	)
	(segment
		(start 280.240994 -217.290904)
		(end 279.816814 -216.866724)
		(width 0.18288)
		(layer "In6.Cu")
		(net "M_C_CPU0_SB_DQ<12>")
	)
	(segment
		(start 333.453486 -235.459778)
		(end 333.445104 -235.454952)
		(width 0.088646)
		(layer "In6.Cu")
		(net "M_C_CPU0_SB_DQ<12>")
	)
	(segment
		(start 317.048896 -225.041714)
		(end 314.22975 -222.222568)
		(width 0.18288)
		(layer "In6.Cu")
		(net "M_C_CPU0_SB_DQ<12>")
	)
	(segment
		(start 314.22975 -222.222568)
		(end 312.276236 -222.222568)
		(width 0.18288)
		(layer "In6.Cu")
		(net "M_C_CPU0_SB_DQ<12>")
	)
	(segment
		(start 293.929054 -218.860116)
		(end 290.790884 -218.860116)
		(width 0.18288)
		(layer "In6.Cu")
		(net "M_C_CPU0_SB_DQ<12>")
	)
	(segment
		(start 338.247482 -236.273594)
		(end 338.23275 -236.28223)
		(width 0.088646)
		(layer "In6.Cu")
		(net "M_C_CPU0_SB_DQ<12>")
	)
	(segment
		(start 310.758078 -220.70441)
		(end 309.777892 -220.70441)
		(width 0.18288)
		(layer "In6.Cu")
		(net "M_C_CPU0_SB_DQ<12>")
	)
	(segment
		(start 341.066882 -236.273594)
		(end 341.05215 -236.28223)
		(width 0.088646)
		(layer "In6.Cu")
		(net "M_C_CPU0_SB_DQ<12>")
	)
	(segment
		(start 290.790884 -218.860116)
		(end 289.931602 -218.000834)
		(width 0.18288)
		(layer "In6.Cu")
		(net "M_C_CPU0_SB_DQ<12>")
	)
	(segment
		(start 334.396334 -235.461556)
		(end 334.393032 -235.459778)
		(width 0.088646)
		(layer "In6.Cu")
		(net "M_C_CPU0_SB_DQ<12>")
	)
	(segment
		(start 334.580484 -235.794042)
		(end 334.580484 -235.784136)
		(width 0.088646)
		(layer "In6.Cu")
		(net "M_C_CPU0_SB_DQ<12>")
	)
	(segment
		(start 309.777892 -220.70441)
		(end 308.012338 -218.938856)
		(width 0.18288)
		(layer "In6.Cu")
		(net "M_C_CPU0_SB_DQ<12>")
	)
	(segment
		(start 287.874202 -217.291412)
		(end 287.86328 -217.291412)
		(width 0.18288)
		(layer "In6.Cu")
		(net "M_C_CPU0_SB_DQ<12>")
	)
	(segment
		(start 337.307682 -236.273594)
		(end 337.297268 -236.27969)
		(width 0.088646)
		(layer "In6.Cu")
		(net "M_C_CPU0_SB_DQ<12>")
	)
	(segment
		(start 304.830734 -219.567506)
		(end 304.830734 -219.121736)
		(width 0.18288)
		(layer "In6.Cu")
		(net "M_C_CPU0_SB_DQ<12>")
	)
	(segment
		(start 287.862772 -217.290904)
		(end 280.240994 -217.290904)
		(width 0.18288)
		(layer "In6.Cu")
		(net "M_C_CPU0_SB_DQ<12>")
	)
	(segment
		(start 304.647854 -218.938856)
		(end 303.956974 -218.938856)
		(width 0.18288)
		(layer "In6.Cu")
		(net "M_C_CPU0_SB_DQ<12>")
	)
	(segment
		(start 317.048896 -227.689156)
		(end 317.048896 -225.041714)
		(width 0.18288)
		(layer "In6.Cu")
		(net "M_C_CPU0_SB_DQ<12>")
	)
	(arc
		(start 342.381332 -236.273594)
		(mid 342.194134 -236.223451)
		(end 342.006936 -236.273594)
		(width 0.088646)
		(layer "In6.Cu")
		(net "M_C_CPU0_SB_DQ<12>")
	)
	(arc
		(start 335.802732 -236.273594)
		(mid 335.615534 -236.223451)
		(end 335.428336 -236.273594)
		(width 0.088646)
		(layer "In6.Cu")
		(net "M_C_CPU0_SB_DQ<12>")
	)
	(arc
		(start 338.621878 -236.273594)
		(mid 338.43468 -236.223451)
		(end 338.247482 -236.273594)
		(width 0.088646)
		(layer "In6.Cu")
		(net "M_C_CPU0_SB_DQ<12>")
	)
	(arc
		(start 340.501478 -236.273594)
		(mid 340.31428 -236.223451)
		(end 340.127082 -236.273594)
		(width 0.088646)
		(layer "In6.Cu")
		(net "M_C_CPU0_SB_DQ<12>")
	)
	(arc
		(start 334.580484 -235.784136)
		(mid 334.531209 -235.59841)
		(end 334.396334 -235.461556)
		(width 0.088646)
		(layer "In6.Cu")
		(net "M_C_CPU0_SB_DQ<12>")
	)
	(arc
		(start 337.297268 -236.27969)
		(mid 337.01909 -236.349382)
		(end 336.742532 -236.273594)
		(width 0.088646)
		(layer "In6.Cu")
		(net "M_C_CPU0_SB_DQ<12>")
	)
	(arc
		(start 333.078836 -235.459778)
		(mid 332.802023 -235.535648)
		(end 332.523592 -235.465874)
		(width 0.088646)
		(layer "In6.Cu")
		(net "M_C_CPU0_SB_DQ<12>")
	)
	(arc
		(start 334.862932 -236.273594)
		(mid 334.658597 -236.070989)
		(end 334.580484 -235.794042)
		(width 0.088646)
		(layer "In6.Cu")
		(net "M_C_CPU0_SB_DQ<12>")
	)
	(arc
		(start 340.11235 -236.28223)
		(mid 339.835909 -236.349396)
		(end 339.561678 -236.273594)
		(width 0.088646)
		(layer "In6.Cu")
		(net "M_C_CPU0_SB_DQ<12>")
	)
	(arc
		(start 333.445104 -235.454952)
		(mid 333.261342 -235.409552)
		(end 333.078836 -235.459778)
		(width 0.088646)
		(layer "In6.Cu")
		(net "M_C_CPU0_SB_DQ<12>")
	)
	(arc
		(start 337.682078 -236.273594)
		(mid 337.49488 -236.223451)
		(end 337.307682 -236.273594)
		(width 0.088646)
		(layer "In6.Cu")
		(net "M_C_CPU0_SB_DQ<12>")
	)
	(arc
		(start 336.742532 -236.273594)
		(mid 336.555334 -236.223451)
		(end 336.368136 -236.273594)
		(width 0.088646)
		(layer "In6.Cu")
		(net "M_C_CPU0_SB_DQ<12>")
	)
	(arc
		(start 335.428336 -236.273594)
		(mid 335.145634 -236.34937)
		(end 334.862932 -236.273594)
		(width 0.088646)
		(layer "In6.Cu")
		(net "M_C_CPU0_SB_DQ<12>")
	)
	(arc
		(start 341.996522 -236.27969)
		(mid 341.71809 -236.349504)
		(end 341.441278 -236.273594)
		(width 0.088646)
		(layer "In6.Cu")
		(net "M_C_CPU0_SB_DQ<12>")
	)
	(arc
		(start 332.523592 -235.465874)
		(mid 332.428748 -235.423723)
		(end 332.32598 -235.409232)
		(width 0.088646)
		(layer "In6.Cu")
		(net "M_C_CPU0_SB_DQ<12>")
	)
	(arc
		(start 339.187282 -236.273594)
		(mid 338.90458 -236.349336)
		(end 338.621878 -236.273594)
		(width 0.088646)
		(layer "In6.Cu")
		(net "M_C_CPU0_SB_DQ<12>")
	)
	(arc
		(start 341.05215 -236.28223)
		(mid 340.775709 -236.349396)
		(end 340.501478 -236.273594)
		(width 0.088646)
		(layer "In6.Cu")
		(net "M_C_CPU0_SB_DQ<12>")
	)
	(arc
		(start 343.13368 -236.597952)
		(mid 342.748054 -236.457696)
		(end 342.381332 -236.273594)
		(width 0.088646)
		(layer "In6.Cu")
		(net "M_C_CPU0_SB_DQ<12>")
	)
	(arc
		(start 341.441278 -236.273594)
		(mid 341.25408 -236.223451)
		(end 341.066882 -236.273594)
		(width 0.088646)
		(layer "In6.Cu")
		(net "M_C_CPU0_SB_DQ<12>")
	)
	(arc
		(start 334.38465 -235.454952)
		(mid 334.201142 -235.409674)
		(end 334.01889 -235.459778)
		(width 0.088646)
		(layer "In6.Cu")
		(net "M_C_CPU0_SB_DQ<12>")
	)
	(arc
		(start 334.01889 -235.459778)
		(mid 333.736188 -235.535554)
		(end 333.453486 -235.459778)
		(width 0.088646)
		(layer "In6.Cu")
		(net "M_C_CPU0_SB_DQ<12>")
	)
	(arc
		(start 336.368136 -236.273594)
		(mid 336.085434 -236.349336)
		(end 335.802732 -236.273594)
		(width 0.088646)
		(layer "In6.Cu")
		(net "M_C_CPU0_SB_DQ<12>")
	)
	(arc
		(start 338.23275 -236.28223)
		(mid 337.956309 -236.349396)
		(end 337.682078 -236.273594)
		(width 0.088646)
		(layer "In6.Cu")
		(net "M_C_CPU0_SB_DQ<12>")
	)
	(arc
		(start 339.561678 -236.273594)
		(mid 339.37448 -236.223451)
		(end 339.187282 -236.273594)
		(width 0.088646)
		(layer "In6.Cu")
		(net "M_C_CPU0_SB_DQ<12>")
	)
	(segment
		(start 277.091394 -220.56344)
		(end 277.091394 -220.392752)
		(width 0.20066)
		(layer "F.Cu")
		(net "M_C_CPU0_SB_DQ<11>")
	)
	(segment
		(start 280.73477 -220.26245)
		(end 280.606246 -220.390974)
		(width 0.20066)
		(layer "F.Cu")
		(net "M_C_CPU0_SB_DQ<11>")
	)
	(segment
		(start 277.58771 -220.705934)
		(end 277.233888 -220.705934)
		(width 0.20066)
		(layer "F.Cu")
		(net "M_C_CPU0_SB_DQ<11>")
	)
	(segment
		(start 345.01328 -238.76127)
		(end 345.01328 -238.225584)
		(width 0.20066)
		(layer "F.Cu")
		(net "M_C_CPU0_SB_DQ<11>")
	)
	(segment
		(start 282.811982 -220.266768)
		(end 281.99588 -220.266768)
		(width 0.20066)
		(layer "F.Cu")
		(net "M_C_CPU0_SB_DQ<11>")
	)
	(segment
		(start 280.606246 -220.542612)
		(end 280.457148 -220.69171)
		(width 0.20066)
		(layer "F.Cu")
		(net "M_C_CPU0_SB_DQ<11>")
	)
	(segment
		(start 345.013534 -238.761524)
		(end 345.01328 -238.76127)
		(width 0.20066)
		(layer "F.Cu")
		(net "M_C_CPU0_SB_DQ<11>")
	)
	(segment
		(start 277.233888 -220.705934)
		(end 277.091394 -220.56344)
		(width 0.20066)
		(layer "F.Cu")
		(net "M_C_CPU0_SB_DQ<11>")
	)
	(segment
		(start 276.96541 -220.266768)
		(end 275.268182 -220.266768)
		(width 0.20066)
		(layer "F.Cu")
		(net "M_C_CPU0_SB_DQ<11>")
	)
	(segment
		(start 277.839932 -220.69171)
		(end 277.601934 -220.69171)
		(width 0.101854)
		(layer "F.Cu")
		(net "M_C_CPU0_SB_DQ<11>")
	)
	(segment
		(start 283.916882 -220.266768)
		(end 282.811982 -220.266768)
		(width 0.20066)
		(layer "F.Cu")
		(net "M_C_CPU0_SB_DQ<11>")
	)
	(segment
		(start 277.601934 -220.69171)
		(end 277.58771 -220.705934)
		(width 0.101854)
		(layer "F.Cu")
		(net "M_C_CPU0_SB_DQ<11>")
	)
	(segment
		(start 280.606246 -220.390974)
		(end 280.606246 -220.542612)
		(width 0.20066)
		(layer "F.Cu")
		(net "M_C_CPU0_SB_DQ<11>")
	)
	(segment
		(start 281.129994 -220.26245)
		(end 280.73477 -220.26245)
		(width 0.20066)
		(layer "F.Cu")
		(net "M_C_CPU0_SB_DQ<11>")
	)
	(segment
		(start 281.788362 -220.474286)
		(end 281.34183 -220.474286)
		(width 0.20066)
		(layer "F.Cu")
		(net "M_C_CPU0_SB_DQ<11>")
	)
	(segment
		(start 277.091394 -220.392752)
		(end 276.96541 -220.266768)
		(width 0.20066)
		(layer "F.Cu")
		(net "M_C_CPU0_SB_DQ<11>")
	)
	(segment
		(start 280.457148 -220.69171)
		(end 279.912826 -220.69171)
		(width 0.20066)
		(layer "F.Cu")
		(net "M_C_CPU0_SB_DQ<11>")
	)
	(segment
		(start 281.34183 -220.474286)
		(end 281.129994 -220.26245)
		(width 0.20066)
		(layer "F.Cu")
		(net "M_C_CPU0_SB_DQ<11>")
	)
	(segment
		(start 281.99588 -220.266768)
		(end 281.788362 -220.474286)
		(width 0.20066)
		(layer "F.Cu")
		(net "M_C_CPU0_SB_DQ<11>")
	)
	(segment
		(start 279.912826 -220.69171)
		(end 277.839932 -220.69171)
		(width 0.1016)
		(layer "F.Cu")
		(net "M_C_CPU0_SB_DQ<11>")
	)
	(segment
		(start 306.950872 -224.0915)
		(end 306.767992 -223.90862)
		(width 0.18288)
		(layer "In6.Cu")
		(net "M_C_CPU0_SB_DQ<11>")
	)
	(segment
		(start 306.077112 -223.491298)
		(end 306.077112 -223.90862)
		(width 0.18288)
		(layer "In6.Cu")
		(net "M_C_CPU0_SB_DQ<11>")
	)
	(segment
		(start 333.938118 -238.541306)
		(end 333.923386 -238.549942)
		(width 0.088646)
		(layer "In6.Cu")
		(net "M_C_CPU0_SB_DQ<11>")
	)
	(segment
		(start 304.187352 -224.0915)
		(end 304.004472 -223.90862)
		(width 0.18288)
		(layer "In6.Cu")
		(net "M_C_CPU0_SB_DQ<11>")
	)
	(segment
		(start 341.066882 -238.549942)
		(end 341.05215 -238.541306)
		(width 0.088646)
		(layer "In6.Cu")
		(net "M_C_CPU0_SB_DQ<11>")
	)
	(segment
		(start 297.18127 -223.241616)
		(end 293.981124 -223.241616)
		(width 0.18288)
		(layer "In6.Cu")
		(net "M_C_CPU0_SB_DQ<11>")
	)
	(segment
		(start 301.903384 -224.0915)
		(end 301.720504 -223.90862)
		(width 0.18288)
		(layer "In6.Cu")
		(net "M_C_CPU0_SB_DQ<11>")
	)
	(segment
		(start 330.775564 -236.013752)
		(end 321.995038 -236.013752)
		(width 0.18288)
		(layer "In6.Cu")
		(net "M_C_CPU0_SB_DQ<11>")
	)
	(segment
		(start 306.259992 -223.308418)
		(end 306.077112 -223.491298)
		(width 0.18288)
		(layer "In6.Cu")
		(net "M_C_CPU0_SB_DQ<11>")
	)
	(segment
		(start 305.894232 -224.0915)
		(end 305.569112 -224.0915)
		(width 0.18288)
		(layer "In6.Cu")
		(net "M_C_CPU0_SB_DQ<11>")
	)
	(segment
		(start 311.280048 -226.512374)
		(end 311.280048 -225.91395)
		(width 0.18288)
		(layer "In6.Cu")
		(net "M_C_CPU0_SB_DQ<11>")
	)
	(segment
		(start 288.267394 -220.756226)
		(end 286.644842 -220.756226)
		(width 0.18288)
		(layer "In6.Cu")
		(net "M_C_CPU0_SB_DQ<11>")
	)
	(segment
		(start 286.644842 -220.756226)
		(end 286.461962 -220.573346)
		(width 0.18288)
		(layer "In6.Cu")
		(net "M_C_CPU0_SB_DQ<11>")
	)
	(segment
		(start 289.571176 -221.634812)
		(end 289.14598 -221.634812)
		(width 0.18288)
		(layer "In6.Cu")
		(net "M_C_CPU0_SB_DQ<11>")
	)
	(segment
		(start 298.031154 -224.0915)
		(end 297.18127 -223.241616)
		(width 0.18288)
		(layer "In6.Cu")
		(net "M_C_CPU0_SB_DQ<11>")
	)
	(segment
		(start 342.952578 -237.89767)
		(end 342.93175 -237.909862)
		(width 0.088646)
		(layer "In6.Cu")
		(net "M_C_CPU0_SB_DQ<11>")
	)
	(segment
		(start 304.004472 -223.90862)
		(end 304.004472 -223.491298)
		(width 0.18288)
		(layer "In6.Cu")
		(net "M_C_CPU0_SB_DQ<11>")
	)
	(segment
		(start 305.569112 -224.0915)
		(end 305.386232 -223.90862)
		(width 0.18288)
		(layer "In6.Cu")
		(net "M_C_CPU0_SB_DQ<11>")
	)
	(segment
		(start 337.307682 -238.549942)
		(end 337.29295 -238.541306)
		(width 0.088646)
		(layer "In6.Cu")
		(net "M_C_CPU0_SB_DQ<11>")
	)
	(segment
		(start 305.203352 -223.308418)
		(end 304.878232 -223.308418)
		(width 0.18288)
		(layer "In6.Cu")
		(net "M_C_CPU0_SB_DQ<11>")
	)
	(segment
		(start 333.084932 -237.739682)
		(end 333.078836 -237.736126)
		(width 0.088646)
		(layer "In6.Cu")
		(net "M_C_CPU0_SB_DQ<11>")
	)
	(segment
		(start 331.831696 -237.786926)
		(end 331.701394 -237.656624)
		(width 0.088646)
		(layer "In6.Cu")
		(net "M_C_CPU0_SB_DQ<11>")
	)
	(segment
		(start 307.236622 -224.0915)
		(end 306.950872 -224.0915)
		(width 0.18288)
		(layer "In6.Cu")
		(net "M_C_CPU0_SB_DQ<11>")
	)
	(segment
		(start 331.233018 -236.733842)
		(end 331.233018 -236.492796)
		(width 0.088646)
		(layer "In6.Cu")
		(net "M_C_CPU0_SB_DQ<11>")
	)
	(segment
		(start 286.461962 -220.573346)
		(end 286.461962 -220.292168)
		(width 0.18288)
		(layer "In6.Cu")
		(net "M_C_CPU0_SB_DQ<11>")
	)
	(segment
		(start 332.32598 -237.786926)
		(end 331.831696 -237.786926)
		(width 0.088646)
		(layer "In6.Cu")
		(net "M_C_CPU0_SB_DQ<11>")
	)
	(segment
		(start 293.13124 -222.391732)
		(end 290.328096 -222.391732)
		(width 0.18288)
		(layer "In6.Cu")
		(net "M_C_CPU0_SB_DQ<11>")
	)
	(segment
		(start 336.367882 -238.549942)
		(end 336.357468 -238.543846)
		(width 0.088646)
		(layer "In6.Cu")
		(net "M_C_CPU0_SB_DQ<11>")
	)
	(segment
		(start 305.386232 -223.491298)
		(end 305.203352 -223.308418)
		(width 0.18288)
		(layer "In6.Cu")
		(net "M_C_CPU0_SB_DQ<11>")
	)
	(segment
		(start 303.496472 -223.308418)
		(end 303.313592 -223.491298)
		(width 0.18288)
		(layer "In6.Cu")
		(net "M_C_CPU0_SB_DQ<11>")
	)
	(segment
		(start 284.40634 -220.756226)
		(end 283.916882 -220.266768)
		(width 0.18288)
		(layer "In6.Cu")
		(net "M_C_CPU0_SB_DQ<11>")
	)
	(segment
		(start 306.585112 -223.308418)
		(end 306.259992 -223.308418)
		(width 0.18288)
		(layer "In6.Cu")
		(net "M_C_CPU0_SB_DQ<11>")
	)
	(segment
		(start 338.247482 -238.549942)
		(end 338.23275 -238.541306)
		(width 0.088646)
		(layer "In6.Cu")
		(net "M_C_CPU0_SB_DQ<11>")
	)
	(segment
		(start 331.701394 -237.656624)
		(end 331.701394 -237.202218)
		(width 0.088646)
		(layer "In6.Cu")
		(net "M_C_CPU0_SB_DQ<11>")
	)
	(segment
		(start 313.8932 -228.342952)
		(end 313.625738 -228.07549)
		(width 0.18288)
		(layer "In6.Cu")
		(net "M_C_CPU0_SB_DQ<11>")
	)
	(segment
		(start 290.328096 -222.391732)
		(end 289.571176 -221.634812)
		(width 0.18288)
		(layer "In6.Cu")
		(net "M_C_CPU0_SB_DQ<11>")
	)
	(segment
		(start 293.981124 -223.241616)
		(end 293.13124 -222.391732)
		(width 0.18288)
		(layer "In6.Cu")
		(net "M_C_CPU0_SB_DQ<11>")
	)
	(segment
		(start 333.54899 -238.549942)
		(end 333.5401 -238.544862)
		(width 0.088646)
		(layer "In6.Cu")
		(net "M_C_CPU0_SB_DQ<11>")
	)
	(segment
		(start 311.759854 -226.99218)
		(end 311.280048 -226.512374)
		(width 0.18288)
		(layer "In6.Cu")
		(net "M_C_CPU0_SB_DQ<11>")
	)
	(segment
		(start 313.625738 -227.595938)
		(end 313.02198 -226.99218)
		(width 0.18288)
		(layer "In6.Cu")
		(net "M_C_CPU0_SB_DQ<11>")
	)
	(segment
		(start 303.130712 -224.0915)
		(end 301.903384 -224.0915)
		(width 0.18288)
		(layer "In6.Cu")
		(net "M_C_CPU0_SB_DQ<11>")
	)
	(segment
		(start 306.077112 -223.90862)
		(end 305.894232 -224.0915)
		(width 0.18288)
		(layer "In6.Cu")
		(net "M_C_CPU0_SB_DQ<11>")
	)
	(segment
		(start 285.771082 -220.292168)
		(end 285.771082 -220.573346)
		(width 0.18288)
		(layer "In6.Cu")
		(net "M_C_CPU0_SB_DQ<11>")
	)
	(segment
		(start 286.279082 -220.109288)
		(end 285.953962 -220.109288)
		(width 0.18288)
		(layer "In6.Cu")
		(net "M_C_CPU0_SB_DQ<11>")
	)
	(segment
		(start 310.307482 -224.941384)
		(end 308.086506 -224.941384)
		(width 0.18288)
		(layer "In6.Cu")
		(net "M_C_CPU0_SB_DQ<11>")
	)
	(segment
		(start 303.313592 -223.491298)
		(end 303.313592 -223.90862)
		(width 0.18288)
		(layer "In6.Cu")
		(net "M_C_CPU0_SB_DQ<11>")
	)
	(segment
		(start 313.02198 -226.99218)
		(end 311.759854 -226.99218)
		(width 0.18288)
		(layer "In6.Cu")
		(net "M_C_CPU0_SB_DQ<11>")
	)
	(segment
		(start 333.078836 -237.736126)
		(end 333.064104 -237.72749)
		(width 0.088646)
		(layer "In6.Cu")
		(net "M_C_CPU0_SB_DQ<11>")
	)
	(segment
		(start 330.995274 -236.013752)
		(end 330.775564 -236.013752)
		(width 0.088646)
		(layer "In6.Cu")
		(net "M_C_CPU0_SB_DQ<11>")
	)
	(segment
		(start 314.324238 -228.342952)
		(end 313.8932 -228.342952)
		(width 0.18288)
		(layer "In6.Cu")
		(net "M_C_CPU0_SB_DQ<11>")
	)
	(segment
		(start 300.846744 -224.0915)
		(end 298.031154 -224.0915)
		(width 0.18288)
		(layer "In6.Cu")
		(net "M_C_CPU0_SB_DQ<11>")
	)
	(segment
		(start 303.821592 -223.308418)
		(end 303.496472 -223.308418)
		(width 0.18288)
		(layer "In6.Cu")
		(net "M_C_CPU0_SB_DQ<11>")
	)
	(segment
		(start 304.695352 -223.491298)
		(end 304.695352 -223.90862)
		(width 0.18288)
		(layer "In6.Cu")
		(net "M_C_CPU0_SB_DQ<11>")
	)
	(segment
		(start 286.461962 -220.292168)
		(end 286.279082 -220.109288)
		(width 0.18288)
		(layer "In6.Cu")
		(net "M_C_CPU0_SB_DQ<11>")
	)
	(segment
		(start 303.313592 -223.90862)
		(end 303.130712 -224.0915)
		(width 0.18288)
		(layer "In6.Cu")
		(net "M_C_CPU0_SB_DQ<11>")
	)
	(segment
		(start 304.512472 -224.0915)
		(end 304.187352 -224.0915)
		(width 0.18288)
		(layer "In6.Cu")
		(net "M_C_CPU0_SB_DQ<11>")
	)
	(segment
		(start 306.767992 -223.491298)
		(end 306.585112 -223.308418)
		(width 0.18288)
		(layer "In6.Cu")
		(net "M_C_CPU0_SB_DQ<11>")
	)
	(segment
		(start 331.146404 -236.164882)
		(end 330.995274 -236.013752)
		(width 0.088646)
		(layer "In6.Cu")
		(net "M_C_CPU0_SB_DQ<11>")
	)
	(segment
		(start 340.127082 -238.549942)
		(end 340.116668 -238.543846)
		(width 0.088646)
		(layer "In6.Cu")
		(net "M_C_CPU0_SB_DQ<11>")
	)
	(segment
		(start 304.878232 -223.308418)
		(end 304.695352 -223.491298)
		(width 0.18288)
		(layer "In6.Cu")
		(net "M_C_CPU0_SB_DQ<11>")
	)
	(segment
		(start 301.029624 -223.90862)
		(end 300.846744 -224.0915)
		(width 0.18288)
		(layer "In6.Cu")
		(net "M_C_CPU0_SB_DQ<11>")
	)
	(segment
		(start 285.771082 -220.573346)
		(end 285.588202 -220.756226)
		(width 0.18288)
		(layer "In6.Cu")
		(net "M_C_CPU0_SB_DQ<11>")
	)
	(segment
		(start 308.086506 -224.941384)
		(end 307.236622 -224.0915)
		(width 0.18288)
		(layer "In6.Cu")
		(net "M_C_CPU0_SB_DQ<11>")
	)
	(segment
		(start 331.146404 -236.406182)
		(end 331.146404 -236.164882)
		(width 0.088646)
		(layer "In6.Cu")
		(net "M_C_CPU0_SB_DQ<11>")
	)
	(segment
		(start 304.004472 -223.491298)
		(end 303.821592 -223.308418)
		(width 0.18288)
		(layer "In6.Cu")
		(net "M_C_CPU0_SB_DQ<11>")
	)
	(segment
		(start 301.720504 -223.90862)
		(end 301.720504 -223.679004)
		(width 0.18288)
		(layer "In6.Cu")
		(net "M_C_CPU0_SB_DQ<11>")
	)
	(segment
		(start 301.720504 -223.679004)
		(end 301.537624 -223.496124)
		(width 0.18288)
		(layer "In6.Cu")
		(net "M_C_CPU0_SB_DQ<11>")
	)
	(segment
		(start 344.658696 -238.130588)
		(end 344.25509 -237.89767)
		(width 0.088646)
		(layer "In6.Cu")
		(net "M_C_CPU0_SB_DQ<11>")
	)
	(segment
		(start 301.212504 -223.496124)
		(end 301.029624 -223.679004)
		(width 0.18288)
		(layer "In6.Cu")
		(net "M_C_CPU0_SB_DQ<11>")
	)
	(segment
		(start 331.233018 -236.492796)
		(end 331.146404 -236.406182)
		(width 0.088646)
		(layer "In6.Cu")
		(net "M_C_CPU0_SB_DQ<11>")
	)
	(segment
		(start 342.006682 -238.549942)
		(end 341.99195 -238.541306)
		(width 0.088646)
		(layer "In6.Cu")
		(net "M_C_CPU0_SB_DQ<11>")
	)
	(segment
		(start 289.14598 -221.634812)
		(end 288.267394 -220.756226)
		(width 0.18288)
		(layer "In6.Cu")
		(net "M_C_CPU0_SB_DQ<11>")
	)
	(segment
		(start 304.695352 -223.90862)
		(end 304.512472 -224.0915)
		(width 0.18288)
		(layer "In6.Cu")
		(net "M_C_CPU0_SB_DQ<11>")
	)
	(segment
		(start 301.537624 -223.496124)
		(end 301.212504 -223.496124)
		(width 0.18288)
		(layer "In6.Cu")
		(net "M_C_CPU0_SB_DQ<11>")
	)
	(segment
		(start 313.625738 -228.07549)
		(end 313.625738 -227.595938)
		(width 0.18288)
		(layer "In6.Cu")
		(net "M_C_CPU0_SB_DQ<11>")
	)
	(segment
		(start 301.029624 -223.679004)
		(end 301.029624 -223.90862)
		(width 0.18288)
		(layer "In6.Cu")
		(net "M_C_CPU0_SB_DQ<11>")
	)
	(segment
		(start 331.701394 -237.202218)
		(end 331.233018 -236.733842)
		(width 0.088646)
		(layer "In6.Cu")
		(net "M_C_CPU0_SB_DQ<11>")
	)
	(segment
		(start 285.588202 -220.756226)
		(end 284.40634 -220.756226)
		(width 0.18288)
		(layer "In6.Cu")
		(net "M_C_CPU0_SB_DQ<11>")
	)
	(segment
		(start 285.953962 -220.109288)
		(end 285.771082 -220.292168)
		(width 0.18288)
		(layer "In6.Cu")
		(net "M_C_CPU0_SB_DQ<11>")
	)
	(segment
		(start 306.767992 -223.90862)
		(end 306.767992 -223.491298)
		(width 0.18288)
		(layer "In6.Cu")
		(net "M_C_CPU0_SB_DQ<11>")
	)
	(segment
		(start 305.386232 -223.90862)
		(end 305.386232 -223.491298)
		(width 0.18288)
		(layer "In6.Cu")
		(net "M_C_CPU0_SB_DQ<11>")
	)
	(segment
		(start 311.280048 -225.91395)
		(end 310.307482 -224.941384)
		(width 0.18288)
		(layer "In6.Cu")
		(net "M_C_CPU0_SB_DQ<11>")
	)
	(segment
		(start 321.995038 -236.013752)
		(end 314.324238 -228.342952)
		(width 0.18288)
		(layer "In6.Cu")
		(net "M_C_CPU0_SB_DQ<11>")
	)
	(segment
		(start 339.187536 -238.549942)
		(end 339.177122 -238.543846)
		(width 0.088646)
		(layer "In6.Cu")
		(net "M_C_CPU0_SB_DQ<11>")
	)
	(segment
		(start 334.8736 -238.543846)
		(end 334.863186 -238.549942)
		(width 0.088646)
		(layer "In6.Cu")
		(net "M_C_CPU0_SB_DQ<11>")
	)
	(arc
		(start 333.5401 -238.544862)
		(mid 333.409186 -238.408502)
		(end 333.361538 -238.225584)
		(width 0.088646)
		(layer "In6.Cu")
		(net "M_C_CPU0_SB_DQ<11>")
	)
	(arc
		(start 340.116668 -238.543846)
		(mid 339.83849 -238.474123)
		(end 339.561932 -238.549942)
		(width 0.088646)
		(layer "In6.Cu")
		(net "M_C_CPU0_SB_DQ<11>")
	)
	(arc
		(start 334.48879 -238.549942)
		(mid 334.214591 -238.474107)
		(end 333.938118 -238.541306)
		(width 0.088646)
		(layer "In6.Cu")
		(net "M_C_CPU0_SB_DQ<11>")
	)
	(arc
		(start 339.177122 -238.543846)
		(mid 338.89869 -238.474)
		(end 338.621878 -238.549942)
		(width 0.088646)
		(layer "In6.Cu")
		(net "M_C_CPU0_SB_DQ<11>")
	)
	(arc
		(start 342.381078 -238.549942)
		(mid 342.19388 -238.600085)
		(end 342.006682 -238.549942)
		(width 0.088646)
		(layer "In6.Cu")
		(net "M_C_CPU0_SB_DQ<11>")
	)
	(arc
		(start 336.357468 -238.543846)
		(mid 336.07929 -238.474123)
		(end 335.802732 -238.549942)
		(width 0.088646)
		(layer "In6.Cu")
		(net "M_C_CPU0_SB_DQ<11>")
	)
	(arc
		(start 345.01328 -238.225584)
		(mid 344.829737 -238.201421)
		(end 344.658696 -238.130588)
		(width 0.088646)
		(layer "In6.Cu")
		(net "M_C_CPU0_SB_DQ<11>")
	)
	(arc
		(start 333.064104 -237.72749)
		(mid 332.787629 -237.66017)
		(end 332.513432 -237.736126)
		(width 0.088646)
		(layer "In6.Cu")
		(net "M_C_CPU0_SB_DQ<11>")
	)
	(arc
		(start 343.347294 -237.850426)
		(mid 343.145051 -237.833163)
		(end 342.952578 -237.89767)
		(width 0.088646)
		(layer "In6.Cu")
		(net "M_C_CPU0_SB_DQ<11>")
	)
	(arc
		(start 341.05215 -238.541306)
		(mid 340.775675 -238.473986)
		(end 340.501478 -238.549942)
		(width 0.088646)
		(layer "In6.Cu")
		(net "M_C_CPU0_SB_DQ<11>")
	)
	(arc
		(start 338.23275 -238.541306)
		(mid 337.956275 -238.473986)
		(end 337.682078 -238.549942)
		(width 0.088646)
		(layer "In6.Cu")
		(net "M_C_CPU0_SB_DQ<11>")
	)
	(arc
		(start 335.802732 -238.549942)
		(mid 335.615534 -238.600085)
		(end 335.428336 -238.549942)
		(width 0.088646)
		(layer "In6.Cu")
		(net "M_C_CPU0_SB_DQ<11>")
	)
	(arc
		(start 342.712294 -238.180626)
		(mid 342.576134 -238.391692)
		(end 342.381078 -238.549942)
		(width 0.088646)
		(layer "In6.Cu")
		(net "M_C_CPU0_SB_DQ<11>")
	)
	(arc
		(start 340.501478 -238.549942)
		(mid 340.31428 -238.600085)
		(end 340.127082 -238.549942)
		(width 0.088646)
		(layer "In6.Cu")
		(net "M_C_CPU0_SB_DQ<11>")
	)
	(arc
		(start 332.513432 -237.736126)
		(mid 332.423053 -237.773881)
		(end 332.32598 -237.786926)
		(width 0.088646)
		(layer "In6.Cu")
		(net "M_C_CPU0_SB_DQ<11>")
	)
	(arc
		(start 337.29295 -238.541306)
		(mid 337.016475 -238.473986)
		(end 336.742278 -238.549942)
		(width 0.088646)
		(layer "In6.Cu")
		(net "M_C_CPU0_SB_DQ<11>")
	)
	(arc
		(start 342.93175 -237.909862)
		(mid 342.797423 -238.025295)
		(end 342.712294 -238.180626)
		(width 0.088646)
		(layer "In6.Cu")
		(net "M_C_CPU0_SB_DQ<11>")
	)
	(arc
		(start 333.923386 -238.549942)
		(mid 333.736188 -238.600085)
		(end 333.54899 -238.549942)
		(width 0.088646)
		(layer "In6.Cu")
		(net "M_C_CPU0_SB_DQ<11>")
	)
	(arc
		(start 338.621878 -238.549942)
		(mid 338.43468 -238.600085)
		(end 338.247482 -238.549942)
		(width 0.088646)
		(layer "In6.Cu")
		(net "M_C_CPU0_SB_DQ<11>")
	)
	(arc
		(start 344.25509 -237.89767)
		(mid 344.070235 -237.850752)
		(end 343.886282 -237.900972)
		(width 0.088646)
		(layer "In6.Cu")
		(net "M_C_CPU0_SB_DQ<11>")
	)
	(arc
		(start 334.863186 -238.549942)
		(mid 334.675988 -238.600085)
		(end 334.48879 -238.549942)
		(width 0.088646)
		(layer "In6.Cu")
		(net "M_C_CPU0_SB_DQ<11>")
	)
	(arc
		(start 335.428336 -238.549942)
		(mid 335.151777 -238.474199)
		(end 334.8736 -238.543846)
		(width 0.088646)
		(layer "In6.Cu")
		(net "M_C_CPU0_SB_DQ<11>")
	)
	(arc
		(start 337.682078 -238.549942)
		(mid 337.49488 -238.600085)
		(end 337.307682 -238.549942)
		(width 0.088646)
		(layer "In6.Cu")
		(net "M_C_CPU0_SB_DQ<11>")
	)
	(arc
		(start 339.561932 -238.549942)
		(mid 339.374734 -238.600085)
		(end 339.187536 -238.549942)
		(width 0.088646)
		(layer "In6.Cu")
		(net "M_C_CPU0_SB_DQ<11>")
	)
	(arc
		(start 333.361538 -238.225584)
		(mid 333.287547 -237.946018)
		(end 333.084932 -237.739682)
		(width 0.088646)
		(layer "In6.Cu")
		(net "M_C_CPU0_SB_DQ<11>")
	)
	(arc
		(start 341.441278 -238.549942)
		(mid 341.25408 -238.600085)
		(end 341.066882 -238.549942)
		(width 0.088646)
		(layer "In6.Cu")
		(net "M_C_CPU0_SB_DQ<11>")
	)
	(arc
		(start 343.886282 -237.900972)
		(mid 343.608717 -237.96159)
		(end 343.347294 -237.850426)
		(width 0.088646)
		(layer "In6.Cu")
		(net "M_C_CPU0_SB_DQ<11>")
	)
	(arc
		(start 341.99195 -238.541306)
		(mid 341.715475 -238.473986)
		(end 341.441278 -238.549942)
		(width 0.088646)
		(layer "In6.Cu")
		(net "M_C_CPU0_SB_DQ<11>")
	)
	(arc
		(start 336.742278 -238.549942)
		(mid 336.55508 -238.600085)
		(end 336.367882 -238.549942)
		(width 0.088646)
		(layer "In6.Cu")
		(net "M_C_CPU0_SB_DQ<11>")
	)
	(segment
		(start 280.689558 -221.685612)
		(end 280.545794 -221.541848)
		(width 0.20066)
		(layer "F.Cu")
		(net "M_C_CPU0_SB_DQ<10>")
	)
	(segment
		(start 279.912826 -221.541848)
		(end 277.852886 -221.541848)
		(width 0.1016)
		(layer "F.Cu")
		(net "M_C_CPU0_SB_DQ<10>")
	)
	(segment
		(start 280.545794 -221.541848)
		(end 279.912826 -221.541848)
		(width 0.20066)
		(layer "F.Cu")
		(net "M_C_CPU0_SB_DQ<10>")
	)
	(segment
		(start 281.285442 -222.178626)
		(end 280.856944 -222.178626)
		(width 0.20066)
		(layer "F.Cu")
		(net "M_C_CPU0_SB_DQ<10>")
	)
	(segment
		(start 277.58771 -221.531688)
		(end 276.850348 -221.531688)
		(width 0.20066)
		(layer "F.Cu")
		(net "M_C_CPU0_SB_DQ<10>")
	)
	(segment
		(start 277.59787 -221.541848)
		(end 277.58771 -221.531688)
		(width 0.101854)
		(layer "F.Cu")
		(net "M_C_CPU0_SB_DQ<10>")
	)
	(segment
		(start 283.916882 -221.96679)
		(end 282.811982 -221.96679)
		(width 0.20066)
		(layer "F.Cu")
		(net "M_C_CPU0_SB_DQ<10>")
	)
	(segment
		(start 280.856944 -222.178626)
		(end 280.689558 -222.01124)
		(width 0.20066)
		(layer "F.Cu")
		(net "M_C_CPU0_SB_DQ<10>")
	)
	(segment
		(start 344.54338 -239.57534)
		(end 344.543634 -239.575086)
		(width 0.20066)
		(layer "F.Cu")
		(net "M_C_CPU0_SB_DQ<10>")
	)
	(segment
		(start 276.850348 -221.531688)
		(end 276.415246 -221.96679)
		(width 0.20066)
		(layer "F.Cu")
		(net "M_C_CPU0_SB_DQ<10>")
	)
	(segment
		(start 277.852886 -221.541848)
		(end 277.59787 -221.541848)
		(width 0.101854)
		(layer "F.Cu")
		(net "M_C_CPU0_SB_DQ<10>")
	)
	(segment
		(start 280.689558 -222.01124)
		(end 280.689558 -221.685612)
		(width 0.20066)
		(layer "F.Cu")
		(net "M_C_CPU0_SB_DQ<10>")
	)
	(segment
		(start 281.497278 -221.96679)
		(end 281.285442 -222.178626)
		(width 0.20066)
		(layer "F.Cu")
		(net "M_C_CPU0_SB_DQ<10>")
	)
	(segment
		(start 276.415246 -221.96679)
		(end 275.268182 -221.96679)
		(width 0.20066)
		(layer "F.Cu")
		(net "M_C_CPU0_SB_DQ<10>")
	)
	(segment
		(start 282.811982 -221.96679)
		(end 281.497278 -221.96679)
		(width 0.20066)
		(layer "F.Cu")
		(net "M_C_CPU0_SB_DQ<10>")
	)
	(segment
		(start 344.543634 -239.575086)
		(end 344.543634 -239.0394)
		(width 0.20066)
		(layer "F.Cu")
		(net "M_C_CPU0_SB_DQ<10>")
	)
	(segment
		(start 308.386734 -227.308664)
		(end 308.203854 -227.491544)
		(width 0.18288)
		(layer "In6.Cu")
		(net "M_C_CPU0_SB_DQ<10>")
	)
	(segment
		(start 295.611296 -224.625408)
		(end 295.29532 -224.941384)
		(width 0.18288)
		(layer "In6.Cu")
		(net "M_C_CPU0_SB_DQ<10>")
	)
	(segment
		(start 309.077614 -227.308664)
		(end 309.077614 -226.472242)
		(width 0.18288)
		(layer "In6.Cu")
		(net "M_C_CPU0_SB_DQ<10>")
	)
	(segment
		(start 304.943002 -226.655376)
		(end 304.760122 -226.838256)
		(width 0.18288)
		(layer "In6.Cu")
		(net "M_C_CPU0_SB_DQ<10>")
	)
	(segment
		(start 305.451002 -225.613214)
		(end 305.147218 -225.613214)
		(width 0.18288)
		(layer "In6.Cu")
		(net "M_C_CPU0_SB_DQ<10>")
	)
	(segment
		(start 288.540952 -223.231456)
		(end 288.540952 -222.79356)
		(width 0.18288)
		(layer "In6.Cu")
		(net "M_C_CPU0_SB_DQ<10>")
	)
	(segment
		(start 293.287196 -224.941384)
		(end 292.113716 -223.767904)
		(width 0.18288)
		(layer "In6.Cu")
		(net "M_C_CPU0_SB_DQ<10>")
	)
	(segment
		(start 305.147218 -225.613214)
		(end 304.943002 -225.81743)
		(width 0.18288)
		(layer "In6.Cu")
		(net "M_C_CPU0_SB_DQ<10>")
	)
	(segment
		(start 304.943002 -225.81743)
		(end 304.943002 -226.655376)
		(width 0.18288)
		(layer "In6.Cu")
		(net "M_C_CPU0_SB_DQ<10>")
	)
	(segment
		(start 331.276452 -237.834424)
		(end 331.276452 -237.32236)
		(width 0.088646)
		(layer "In6.Cu")
		(net "M_C_CPU0_SB_DQ<10>")
	)
	(segment
		(start 334.407764 -239.355122)
		(end 334.393032 -239.363758)
		(width 0.088646)
		(layer "In6.Cu")
		(net "M_C_CPU0_SB_DQ<10>")
	)
	(segment
		(start 331.916532 -238.474504)
		(end 331.276452 -237.834424)
		(width 0.088646)
		(layer "In6.Cu")
		(net "M_C_CPU0_SB_DQ<10>")
	)
	(segment
		(start 330.963524 -237.009432)
		(end 330.775564 -237.009432)
		(width 0.088646)
		(layer "In6.Cu")
		(net "M_C_CPU0_SB_DQ<10>")
	)
	(segment
		(start 313.480704 -230.043736)
		(end 312.57367 -229.136702)
		(width 0.18288)
		(layer "In6.Cu")
		(net "M_C_CPU0_SB_DQ<10>")
	)
	(segment
		(start 286.629094 -222.473266)
		(end 286.446214 -222.290386)
		(width 0.18288)
		(layer "In6.Cu")
		(net "M_C_CPU0_SB_DQ<10>")
	)
	(segment
		(start 336.287364 -239.355122)
		(end 336.272632 -239.363758)
		(width 0.088646)
		(layer "In6.Cu")
		(net "M_C_CPU0_SB_DQ<10>")
	)
	(segment
		(start 308.569614 -226.289362)
		(end 308.386734 -226.472242)
		(width 0.18288)
		(layer "In6.Cu")
		(net "M_C_CPU0_SB_DQ<10>")
	)
	(segment
		(start 285.938214 -221.811342)
		(end 285.755334 -221.994222)
		(width 0.18288)
		(layer "In6.Cu")
		(net "M_C_CPU0_SB_DQ<10>")
	)
	(segment
		(start 306.63134 -226.838256)
		(end 305.816762 -226.838256)
		(width 0.18288)
		(layer "In6.Cu")
		(net "M_C_CPU0_SB_DQ<10>")
	)
	(segment
		(start 286.446214 -222.290386)
		(end 286.446214 -221.994222)
		(width 0.18288)
		(layer "In6.Cu")
		(net "M_C_CPU0_SB_DQ<10>")
	)
	(segment
		(start 330.775564 -237.009432)
		(end 321.392042 -237.009432)
		(width 0.18288)
		(layer "In6.Cu")
		(net "M_C_CPU0_SB_DQ<10>")
	)
	(segment
		(start 302.962818 -225.791522)
		(end 301.716694 -225.791522)
		(width 0.18288)
		(layer "In6.Cu")
		(net "M_C_CPU0_SB_DQ<10>")
	)
	(segment
		(start 305.633882 -225.796094)
		(end 305.451002 -225.613214)
		(width 0.18288)
		(layer "In6.Cu")
		(net "M_C_CPU0_SB_DQ<10>")
	)
	(segment
		(start 301.350934 -225.22434)
		(end 301.025814 -225.22434)
		(width 0.18288)
		(layer "In6.Cu")
		(net "M_C_CPU0_SB_DQ<10>")
	)
	(segment
		(start 285.755334 -222.290386)
		(end 285.572454 -222.473266)
		(width 0.18288)
		(layer "In6.Cu")
		(net "M_C_CPU0_SB_DQ<10>")
	)
	(segment
		(start 308.894734 -226.289362)
		(end 308.569614 -226.289362)
		(width 0.18288)
		(layer "In6.Cu")
		(net "M_C_CPU0_SB_DQ<10>")
	)
	(segment
		(start 292.113716 -223.767904)
		(end 289.0774 -223.767904)
		(width 0.18288)
		(layer "In6.Cu")
		(net "M_C_CPU0_SB_DQ<10>")
	)
	(segment
		(start 332.891384 -239.0394)
		(end 332.891384 -239.029494)
		(width 0.088646)
		(layer "In6.Cu")
		(net "M_C_CPU0_SB_DQ<10>")
	)
	(segment
		(start 342.859868 -239.358678)
		(end 342.850978 -239.363758)
		(width 0.088646)
		(layer "In6.Cu")
		(net "M_C_CPU0_SB_DQ<10>")
	)
	(segment
		(start 288.540952 -222.79356)
		(end 288.220658 -222.473266)
		(width 0.18288)
		(layer "In6.Cu")
		(net "M_C_CPU0_SB_DQ<10>")
	)
	(segment
		(start 296.293032 -224.941384)
		(end 295.977056 -224.625408)
		(width 0.18288)
		(layer "In6.Cu")
		(net "M_C_CPU0_SB_DQ<10>")
	)
	(segment
		(start 285.572454 -222.473266)
		(end 284.423358 -222.473266)
		(width 0.18288)
		(layer "In6.Cu")
		(net "M_C_CPU0_SB_DQ<10>")
	)
	(segment
		(start 295.977056 -224.625408)
		(end 295.611296 -224.625408)
		(width 0.18288)
		(layer "In6.Cu")
		(net "M_C_CPU0_SB_DQ<10>")
	)
	(segment
		(start 341.921846 -239.357662)
		(end 341.911432 -239.363758)
		(width 0.088646)
		(layer "In6.Cu")
		(net "M_C_CPU0_SB_DQ<10>")
	)
	(segment
		(start 331.276452 -237.32236)
		(end 330.963524 -237.009432)
		(width 0.088646)
		(layer "In6.Cu")
		(net "M_C_CPU0_SB_DQ<10>")
	)
	(segment
		(start 297.235118 -224.941384)
		(end 296.293032 -224.941384)
		(width 0.18288)
		(layer "In6.Cu")
		(net "M_C_CPU0_SB_DQ<10>")
	)
	(segment
		(start 309.077614 -226.472242)
		(end 308.894734 -226.289362)
		(width 0.18288)
		(layer "In6.Cu")
		(net "M_C_CPU0_SB_DQ<10>")
	)
	(segment
		(start 307.284628 -227.491544)
		(end 306.63134 -226.838256)
		(width 0.18288)
		(layer "In6.Cu")
		(net "M_C_CPU0_SB_DQ<10>")
	)
	(segment
		(start 295.29532 -224.941384)
		(end 293.287196 -224.941384)
		(width 0.18288)
		(layer "In6.Cu")
		(net "M_C_CPU0_SB_DQ<10>")
	)
	(segment
		(start 305.816762 -226.838256)
		(end 305.633882 -226.655376)
		(width 0.18288)
		(layer "In6.Cu")
		(net "M_C_CPU0_SB_DQ<10>")
	)
	(segment
		(start 284.423358 -222.473266)
		(end 283.916882 -221.96679)
		(width 0.18288)
		(layer "In6.Cu")
		(net "M_C_CPU0_SB_DQ<10>")
	)
	(segment
		(start 308.203854 -227.491544)
		(end 307.284628 -227.491544)
		(width 0.18288)
		(layer "In6.Cu")
		(net "M_C_CPU0_SB_DQ<10>")
	)
	(segment
		(start 340.046564 -239.355122)
		(end 340.031832 -239.363758)
		(width 0.088646)
		(layer "In6.Cu")
		(net "M_C_CPU0_SB_DQ<10>")
	)
	(segment
		(start 298.085256 -225.791522)
		(end 297.235118 -224.941384)
		(width 0.18288)
		(layer "In6.Cu")
		(net "M_C_CPU0_SB_DQ<10>")
	)
	(segment
		(start 321.392042 -237.009432)
		(end 314.426346 -230.043736)
		(width 0.18288)
		(layer "In6.Cu")
		(net "M_C_CPU0_SB_DQ<10>")
	)
	(segment
		(start 314.426346 -230.043736)
		(end 313.480704 -230.043736)
		(width 0.18288)
		(layer "In6.Cu")
		(net "M_C_CPU0_SB_DQ<10>")
	)
	(segment
		(start 300.660054 -225.791522)
		(end 298.085256 -225.791522)
		(width 0.18288)
		(layer "In6.Cu")
		(net "M_C_CPU0_SB_DQ<10>")
	)
	(segment
		(start 332.32598 -238.474504)
		(end 331.916532 -238.474504)
		(width 0.088646)
		(layer "In6.Cu")
		(net "M_C_CPU0_SB_DQ<10>")
	)
	(segment
		(start 300.842934 -225.608642)
		(end 300.660054 -225.791522)
		(width 0.18288)
		(layer "In6.Cu")
		(net "M_C_CPU0_SB_DQ<10>")
	)
	(segment
		(start 305.633882 -226.655376)
		(end 305.633882 -225.796094)
		(width 0.18288)
		(layer "In6.Cu")
		(net "M_C_CPU0_SB_DQ<10>")
	)
	(segment
		(start 301.025814 -225.22434)
		(end 300.842934 -225.40722)
		(width 0.18288)
		(layer "In6.Cu")
		(net "M_C_CPU0_SB_DQ<10>")
	)
	(segment
		(start 333.467964 -239.355122)
		(end 333.453232 -239.363758)
		(width 0.088646)
		(layer "In6.Cu")
		(net "M_C_CPU0_SB_DQ<10>")
	)
	(segment
		(start 286.446214 -221.994222)
		(end 286.263334 -221.811342)
		(width 0.18288)
		(layer "In6.Cu")
		(net "M_C_CPU0_SB_DQ<10>")
	)
	(segment
		(start 301.533814 -225.40722)
		(end 301.350934 -225.22434)
		(width 0.18288)
		(layer "In6.Cu")
		(net "M_C_CPU0_SB_DQ<10>")
	)
	(segment
		(start 285.755334 -221.994222)
		(end 285.755334 -222.290386)
		(width 0.18288)
		(layer "In6.Cu")
		(net "M_C_CPU0_SB_DQ<10>")
	)
	(segment
		(start 337.227164 -239.355122)
		(end 337.212432 -239.363758)
		(width 0.088646)
		(layer "In6.Cu")
		(net "M_C_CPU0_SB_DQ<10>")
	)
	(segment
		(start 286.263334 -221.811342)
		(end 285.938214 -221.811342)
		(width 0.18288)
		(layer "In6.Cu")
		(net "M_C_CPU0_SB_DQ<10>")
	)
	(segment
		(start 289.0774 -223.767904)
		(end 288.540952 -223.231456)
		(width 0.18288)
		(layer "In6.Cu")
		(net "M_C_CPU0_SB_DQ<10>")
	)
	(segment
		(start 312.57367 -228.586792)
		(end 312.230008 -228.24313)
		(width 0.18288)
		(layer "In6.Cu")
		(net "M_C_CPU0_SB_DQ<10>")
	)
	(segment
		(start 311.43448 -228.24313)
		(end 310.682894 -227.491544)
		(width 0.18288)
		(layer "In6.Cu")
		(net "M_C_CPU0_SB_DQ<10>")
	)
	(segment
		(start 340.986364 -239.355122)
		(end 340.971632 -239.363758)
		(width 0.088646)
		(layer "In6.Cu")
		(net "M_C_CPU0_SB_DQ<10>")
	)
	(segment
		(start 301.716694 -225.791522)
		(end 301.533814 -225.608642)
		(width 0.18288)
		(layer "In6.Cu")
		(net "M_C_CPU0_SB_DQ<10>")
	)
	(segment
		(start 339.106764 -239.355122)
		(end 339.092032 -239.363758)
		(width 0.088646)
		(layer "In6.Cu")
		(net "M_C_CPU0_SB_DQ<10>")
	)
	(segment
		(start 308.386734 -226.472242)
		(end 308.386734 -227.308664)
		(width 0.18288)
		(layer "In6.Cu")
		(net "M_C_CPU0_SB_DQ<10>")
	)
	(segment
		(start 343.703656 -238.64316)
		(end 343.347294 -238.688626)
		(width 0.088646)
		(layer "In6.Cu")
		(net "M_C_CPU0_SB_DQ<10>")
	)
	(segment
		(start 310.682894 -227.491544)
		(end 309.260494 -227.491544)
		(width 0.18288)
		(layer "In6.Cu")
		(net "M_C_CPU0_SB_DQ<10>")
	)
	(segment
		(start 312.230008 -228.24313)
		(end 311.43448 -228.24313)
		(width 0.18288)
		(layer "In6.Cu")
		(net "M_C_CPU0_SB_DQ<10>")
	)
	(segment
		(start 309.260494 -227.491544)
		(end 309.077614 -227.308664)
		(width 0.18288)
		(layer "In6.Cu")
		(net "M_C_CPU0_SB_DQ<10>")
	)
	(segment
		(start 333.078836 -239.363758)
		(end 333.069946 -239.358678)
		(width 0.088646)
		(layer "In6.Cu")
		(net "M_C_CPU0_SB_DQ<10>")
	)
	(segment
		(start 304.760122 -226.838256)
		(end 304.009552 -226.838256)
		(width 0.18288)
		(layer "In6.Cu")
		(net "M_C_CPU0_SB_DQ<10>")
	)
	(segment
		(start 288.220658 -222.473266)
		(end 286.629094 -222.473266)
		(width 0.18288)
		(layer "In6.Cu")
		(net "M_C_CPU0_SB_DQ<10>")
	)
	(segment
		(start 312.57367 -229.136702)
		(end 312.57367 -228.586792)
		(width 0.18288)
		(layer "In6.Cu")
		(net "M_C_CPU0_SB_DQ<10>")
	)
	(segment
		(start 335.347564 -239.355122)
		(end 335.332832 -239.363758)
		(width 0.088646)
		(layer "In6.Cu")
		(net "M_C_CPU0_SB_DQ<10>")
	)
	(segment
		(start 300.842934 -225.40722)
		(end 300.842934 -225.608642)
		(width 0.18288)
		(layer "In6.Cu")
		(net "M_C_CPU0_SB_DQ<10>")
	)
	(segment
		(start 332.326234 -238.47425)
		(end 332.32598 -238.474504)
		(width 0.088646)
		(layer "In6.Cu")
		(net "M_C_CPU0_SB_DQ<10>")
	)
	(segment
		(start 301.533814 -225.608642)
		(end 301.533814 -225.40722)
		(width 0.18288)
		(layer "In6.Cu")
		(net "M_C_CPU0_SB_DQ<10>")
	)
	(segment
		(start 304.009552 -226.838256)
		(end 302.962818 -225.791522)
		(width 0.18288)
		(layer "In6.Cu")
		(net "M_C_CPU0_SB_DQ<10>")
	)
	(arc
		(start 339.657436 -239.363758)
		(mid 339.383237 -239.287923)
		(end 339.106764 -239.355122)
		(width 0.088646)
		(layer "In6.Cu")
		(net "M_C_CPU0_SB_DQ<10>")
	)
	(arc
		(start 342.476582 -239.363758)
		(mid 342.200023 -239.288015)
		(end 341.921846 -239.357662)
		(width 0.088646)
		(layer "In6.Cu")
		(net "M_C_CPU0_SB_DQ<10>")
	)
	(arc
		(start 343.03843 -239.0394)
		(mid 342.990751 -239.2223)
		(end 342.859868 -239.358678)
		(width 0.088646)
		(layer "In6.Cu")
		(net "M_C_CPU0_SB_DQ<10>")
	)
	(arc
		(start 338.717636 -239.363758)
		(mid 338.434934 -239.287982)
		(end 338.152232 -239.363758)
		(width 0.088646)
		(layer "In6.Cu")
		(net "M_C_CPU0_SB_DQ<10>")
	)
	(arc
		(start 338.152232 -239.363758)
		(mid 337.965034 -239.413901)
		(end 337.777836 -239.363758)
		(width 0.088646)
		(layer "In6.Cu")
		(net "M_C_CPU0_SB_DQ<10>")
	)
	(arc
		(start 339.092032 -239.363758)
		(mid 338.904834 -239.413901)
		(end 338.717636 -239.363758)
		(width 0.088646)
		(layer "In6.Cu")
		(net "M_C_CPU0_SB_DQ<10>")
	)
	(arc
		(start 341.537036 -239.363758)
		(mid 341.262837 -239.287923)
		(end 340.986364 -239.355122)
		(width 0.088646)
		(layer "In6.Cu")
		(net "M_C_CPU0_SB_DQ<10>")
	)
	(arc
		(start 334.958436 -239.363758)
		(mid 334.684237 -239.287923)
		(end 334.407764 -239.355122)
		(width 0.088646)
		(layer "In6.Cu")
		(net "M_C_CPU0_SB_DQ<10>")
	)
	(arc
		(start 340.031832 -239.363758)
		(mid 339.844634 -239.413901)
		(end 339.657436 -239.363758)
		(width 0.088646)
		(layer "In6.Cu")
		(net "M_C_CPU0_SB_DQ<10>")
	)
	(arc
		(start 336.838036 -239.363758)
		(mid 336.563837 -239.287923)
		(end 336.287364 -239.355122)
		(width 0.088646)
		(layer "In6.Cu")
		(net "M_C_CPU0_SB_DQ<10>")
	)
	(arc
		(start 333.069946 -239.358678)
		(mid 332.939032 -239.222318)
		(end 332.891384 -239.0394)
		(width 0.088646)
		(layer "In6.Cu")
		(net "M_C_CPU0_SB_DQ<10>")
	)
	(arc
		(start 337.777836 -239.363758)
		(mid 337.503637 -239.287923)
		(end 337.227164 -239.355122)
		(width 0.088646)
		(layer "In6.Cu")
		(net "M_C_CPU0_SB_DQ<10>")
	)
	(arc
		(start 334.393032 -239.363758)
		(mid 334.205834 -239.413901)
		(end 334.018636 -239.363758)
		(width 0.088646)
		(layer "In6.Cu")
		(net "M_C_CPU0_SB_DQ<10>")
	)
	(arc
		(start 344.543634 -239.0394)
		(mid 344.181442 -238.718731)
		(end 343.703656 -238.64316)
		(width 0.088646)
		(layer "In6.Cu")
		(net "M_C_CPU0_SB_DQ<10>")
	)
	(arc
		(start 343.347294 -238.688626)
		(mid 343.126622 -238.805698)
		(end 343.03843 -239.0394)
		(width 0.088646)
		(layer "In6.Cu")
		(net "M_C_CPU0_SB_DQ<10>")
	)
	(arc
		(start 334.018636 -239.363758)
		(mid 333.744437 -239.287923)
		(end 333.467964 -239.355122)
		(width 0.088646)
		(layer "In6.Cu")
		(net "M_C_CPU0_SB_DQ<10>")
	)
	(arc
		(start 340.971632 -239.363758)
		(mid 340.784434 -239.413901)
		(end 340.597236 -239.363758)
		(width 0.088646)
		(layer "In6.Cu")
		(net "M_C_CPU0_SB_DQ<10>")
	)
	(arc
		(start 335.898236 -239.363758)
		(mid 335.624037 -239.287923)
		(end 335.347564 -239.355122)
		(width 0.088646)
		(layer "In6.Cu")
		(net "M_C_CPU0_SB_DQ<10>")
	)
	(arc
		(start 333.453232 -239.363758)
		(mid 333.266034 -239.413901)
		(end 333.078836 -239.363758)
		(width 0.088646)
		(layer "In6.Cu")
		(net "M_C_CPU0_SB_DQ<10>")
	)
	(arc
		(start 341.911432 -239.363758)
		(mid 341.724234 -239.413901)
		(end 341.537036 -239.363758)
		(width 0.088646)
		(layer "In6.Cu")
		(net "M_C_CPU0_SB_DQ<10>")
	)
	(arc
		(start 342.850978 -239.363758)
		(mid 342.66378 -239.413901)
		(end 342.476582 -239.363758)
		(width 0.088646)
		(layer "In6.Cu")
		(net "M_C_CPU0_SB_DQ<10>")
	)
	(arc
		(start 340.597236 -239.363758)
		(mid 340.323037 -239.287923)
		(end 340.046564 -239.355122)
		(width 0.088646)
		(layer "In6.Cu")
		(net "M_C_CPU0_SB_DQ<10>")
	)
	(arc
		(start 332.891384 -239.029494)
		(mid 332.722399 -238.63623)
		(end 332.326234 -238.47425)
		(width 0.088646)
		(layer "In6.Cu")
		(net "M_C_CPU0_SB_DQ<10>")
	)
	(arc
		(start 335.332832 -239.363758)
		(mid 335.145634 -239.413901)
		(end 334.958436 -239.363758)
		(width 0.088646)
		(layer "In6.Cu")
		(net "M_C_CPU0_SB_DQ<10>")
	)
	(arc
		(start 337.212432 -239.363758)
		(mid 337.025234 -239.413901)
		(end 336.838036 -239.363758)
		(width 0.088646)
		(layer "In6.Cu")
		(net "M_C_CPU0_SB_DQ<10>")
	)
	(arc
		(start 336.272632 -239.363758)
		(mid 336.085434 -239.413901)
		(end 335.898236 -239.363758)
		(width 0.088646)
		(layer "In6.Cu")
		(net "M_C_CPU0_SB_DQ<10>")
	)
	(segment
		(start 273.37258 -232.232708)
		(end 273.19986 -232.405428)
		(width 0.20066)
		(layer "F.Cu")
		(net "M_C_CPU0_SB_DQ<0>")
	)
	(segment
		(start 274.152106 -231.741726)
		(end 274.143978 -231.733598)
		(width 0.101854)
		(layer "F.Cu")
		(net "M_C_CPU0_SB_DQ<0>")
	)
	(segment
		(start 343.60358 -243.923058)
		(end 343.603834 -243.922804)
		(width 0.20066)
		(layer "F.Cu")
		(net "M_C_CPU0_SB_DQ<0>")
	)
	(segment
		(start 277.342854 -232.166668)
		(end 276.917912 -231.741726)
		(width 0.20066)
		(layer "F.Cu")
		(net "M_C_CPU0_SB_DQ<0>")
	)
	(segment
		(start 273.37258 -231.943148)
		(end 273.37258 -232.232708)
		(width 0.20066)
		(layer "F.Cu")
		(net "M_C_CPU0_SB_DQ<0>")
	)
	(segment
		(start 274.40001 -231.741726)
		(end 274.152106 -231.741726)
		(width 0.101854)
		(layer "F.Cu")
		(net "M_C_CPU0_SB_DQ<0>")
	)
	(segment
		(start 278.711914 -232.166668)
		(end 277.342854 -232.166668)
		(width 0.20066)
		(layer "F.Cu")
		(net "M_C_CPU0_SB_DQ<0>")
	)
	(segment
		(start 273.19986 -232.405428)
		(end 272.741136 -232.405428)
		(width 0.20066)
		(layer "F.Cu")
		(net "M_C_CPU0_SB_DQ<0>")
	)
	(segment
		(start 343.60358 -244.458744)
		(end 343.60358 -243.923058)
		(width 0.20066)
		(layer "F.Cu")
		(net "M_C_CPU0_SB_DQ<0>")
	)
	(segment
		(start 273.58213 -231.733598)
		(end 273.37258 -231.943148)
		(width 0.20066)
		(layer "F.Cu")
		(net "M_C_CPU0_SB_DQ<0>")
	)
	(segment
		(start 276.469094 -231.741726)
		(end 274.40001 -231.741726)
		(width 0.1016)
		(layer "F.Cu")
		(net "M_C_CPU0_SB_DQ<0>")
	)
	(segment
		(start 272.741136 -232.405428)
		(end 272.502376 -232.166668)
		(width 0.20066)
		(layer "F.Cu")
		(net "M_C_CPU0_SB_DQ<0>")
	)
	(segment
		(start 274.143978 -231.733598)
		(end 273.58213 -231.733598)
		(width 0.20066)
		(layer "F.Cu")
		(net "M_C_CPU0_SB_DQ<0>")
	)
	(segment
		(start 279.816814 -232.166668)
		(end 278.711914 -232.166668)
		(width 0.20066)
		(layer "F.Cu")
		(net "M_C_CPU0_SB_DQ<0>")
	)
	(segment
		(start 272.502376 -232.166668)
		(end 271.168114 -232.166668)
		(width 0.20066)
		(layer "F.Cu")
		(net "M_C_CPU0_SB_DQ<0>")
	)
	(segment
		(start 276.917912 -231.741726)
		(end 276.469094 -231.741726)
		(width 0.20066)
		(layer "F.Cu")
		(net "M_C_CPU0_SB_DQ<0>")
	)
	(segment
		(start 315.21654 -240.364772)
		(end 313.632088 -240.364772)
		(width 0.18288)
		(layer "In6.Cu")
		(net "M_C_CPU0_SB_DQ<0>")
	)
	(segment
		(start 296.208704 -236.841792)
		(end 289.136836 -236.841792)
		(width 0.18288)
		(layer "In6.Cu")
		(net "M_C_CPU0_SB_DQ<0>")
	)
	(segment
		(start 330.397358 -244.464586)
		(end 329.375008 -243.442236)
		(width 0.18288)
		(layer "In6.Cu")
		(net "M_C_CPU0_SB_DQ<0>")
	)
	(segment
		(start 310.483758 -238.541052)
		(end 306.5272 -238.541052)
		(width 0.18288)
		(layer "In6.Cu")
		(net "M_C_CPU0_SB_DQ<0>")
	)
	(segment
		(start 284.617668 -232.591864)
		(end 280.354278 -232.591864)
		(width 0.18288)
		(layer "In6.Cu")
		(net "M_C_CPU0_SB_DQ<0>")
	)
	(segment
		(start 286.04337 -232.368852)
		(end 284.84068 -232.368852)
		(width 0.18288)
		(layer "In6.Cu")
		(net "M_C_CPU0_SB_DQ<0>")
	)
	(segment
		(start 306.5272 -238.541052)
		(end 305.58232 -237.596172)
		(width 0.18288)
		(layer "In6.Cu")
		(net "M_C_CPU0_SB_DQ<0>")
	)
	(segment
		(start 284.84068 -232.368852)
		(end 284.617668 -232.591864)
		(width 0.18288)
		(layer "In6.Cu")
		(net "M_C_CPU0_SB_DQ<0>")
	)
	(segment
		(start 311.233058 -239.290352)
		(end 310.483758 -238.541052)
		(width 0.18288)
		(layer "In6.Cu")
		(net "M_C_CPU0_SB_DQ<0>")
	)
	(segment
		(start 287.957514 -234.282996)
		(end 286.04337 -232.368852)
		(width 0.18288)
		(layer "In6.Cu")
		(net "M_C_CPU0_SB_DQ<0>")
	)
	(segment
		(start 279.929082 -232.166668)
		(end 279.816814 -232.166668)
		(width 0.18288)
		(layer "In6.Cu")
		(net "M_C_CPU0_SB_DQ<0>")
	)
	(segment
		(start 339.187282 -244.412262)
		(end 339.176868 -244.418358)
		(width 0.088646)
		(layer "In6.Cu")
		(net "M_C_CPU0_SB_DQ<0>")
	)
	(segment
		(start 338.247736 -244.412262)
		(end 338.237322 -244.418358)
		(width 0.088646)
		(layer "In6.Cu")
		(net "M_C_CPU0_SB_DQ<0>")
	)
	(segment
		(start 318.294004 -243.442236)
		(end 315.21654 -240.364772)
		(width 0.18288)
		(layer "In6.Cu")
		(net "M_C_CPU0_SB_DQ<0>")
	)
	(segment
		(start 287.957514 -235.66247)
		(end 287.957514 -234.282996)
		(width 0.18288)
		(layer "In6.Cu")
		(net "M_C_CPU0_SB_DQ<0>")
	)
	(segment
		(start 300.739556 -237.596172)
		(end 299.793914 -238.541814)
		(width 0.18288)
		(layer "In6.Cu")
		(net "M_C_CPU0_SB_DQ<0>")
	)
	(segment
		(start 342.958674 -244.40515)
		(end 342.946482 -244.412262)
		(width 0.088646)
		(layer "In6.Cu")
		(net "M_C_CPU0_SB_DQ<0>")
	)
	(segment
		(start 336.367882 -244.412262)
		(end 336.35315 -244.420898)
		(width 0.088646)
		(layer "In6.Cu")
		(net "M_C_CPU0_SB_DQ<0>")
	)
	(segment
		(start 343.26957 -243.882418)
		(end 343.229184 -243.922804)
		(width 0.088646)
		(layer "In6.Cu")
		(net "M_C_CPU0_SB_DQ<0>")
	)
	(segment
		(start 313.632088 -240.364772)
		(end 312.557668 -239.290352)
		(width 0.18288)
		(layer "In6.Cu")
		(net "M_C_CPU0_SB_DQ<0>")
	)
	(segment
		(start 343.603834 -243.922804)
		(end 343.563448 -243.882418)
		(width 0.088646)
		(layer "In6.Cu")
		(net "M_C_CPU0_SB_DQ<0>")
	)
	(segment
		(start 297.908726 -238.541814)
		(end 296.208704 -236.841792)
		(width 0.18288)
		(layer "In6.Cu")
		(net "M_C_CPU0_SB_DQ<0>")
	)
	(segment
		(start 305.58232 -237.596172)
		(end 300.739556 -237.596172)
		(width 0.18288)
		(layer "In6.Cu")
		(net "M_C_CPU0_SB_DQ<0>")
	)
	(segment
		(start 312.557668 -239.290352)
		(end 311.233058 -239.290352)
		(width 0.18288)
		(layer "In6.Cu")
		(net "M_C_CPU0_SB_DQ<0>")
	)
	(segment
		(start 332.164436 -244.464586)
		(end 331.029564 -244.464586)
		(width 0.088646)
		(layer "In6.Cu")
		(net "M_C_CPU0_SB_DQ<0>")
	)
	(segment
		(start 341.066882 -244.412262)
		(end 341.056468 -244.418358)
		(width 0.088646)
		(layer "In6.Cu")
		(net "M_C_CPU0_SB_DQ<0>")
	)
	(segment
		(start 343.563448 -243.882418)
		(end 343.26957 -243.882418)
		(width 0.088646)
		(layer "In6.Cu")
		(net "M_C_CPU0_SB_DQ<0>")
	)
	(segment
		(start 340.127336 -244.412262)
		(end 340.116922 -244.418358)
		(width 0.088646)
		(layer "In6.Cu")
		(net "M_C_CPU0_SB_DQ<0>")
	)
	(segment
		(start 342.006682 -244.412262)
		(end 341.99195 -244.420898)
		(width 0.088646)
		(layer "In6.Cu")
		(net "M_C_CPU0_SB_DQ<0>")
	)
	(segment
		(start 329.375008 -243.442236)
		(end 318.294004 -243.442236)
		(width 0.18288)
		(layer "In6.Cu")
		(net "M_C_CPU0_SB_DQ<0>")
	)
	(segment
		(start 289.136836 -236.841792)
		(end 287.957514 -235.66247)
		(width 0.18288)
		(layer "In6.Cu")
		(net "M_C_CPU0_SB_DQ<0>")
	)
	(segment
		(start 337.307682 -244.412262)
		(end 337.29295 -244.420898)
		(width 0.088646)
		(layer "In6.Cu")
		(net "M_C_CPU0_SB_DQ<0>")
	)
	(segment
		(start 280.354278 -232.591864)
		(end 279.929082 -232.166668)
		(width 0.18288)
		(layer "In6.Cu")
		(net "M_C_CPU0_SB_DQ<0>")
	)
	(segment
		(start 299.793914 -238.541814)
		(end 297.908726 -238.541814)
		(width 0.18288)
		(layer "In6.Cu")
		(net "M_C_CPU0_SB_DQ<0>")
	)
	(segment
		(start 331.029564 -244.464586)
		(end 330.397358 -244.464586)
		(width 0.18288)
		(layer "In6.Cu")
		(net "M_C_CPU0_SB_DQ<0>")
	)
	(arc
		(start 336.35315 -244.420898)
		(mid 336.076675 -244.488218)
		(end 335.802478 -244.412262)
		(width 0.088646)
		(layer "In6.Cu")
		(net "M_C_CPU0_SB_DQ<0>")
	)
	(arc
		(start 341.056468 -244.418358)
		(mid 340.77829 -244.488081)
		(end 340.501732 -244.412262)
		(width 0.088646)
		(layer "In6.Cu")
		(net "M_C_CPU0_SB_DQ<0>")
	)
	(arc
		(start 337.29295 -244.420898)
		(mid 337.016475 -244.488218)
		(end 336.742278 -244.412262)
		(width 0.088646)
		(layer "In6.Cu")
		(net "M_C_CPU0_SB_DQ<0>")
	)
	(arc
		(start 340.116922 -244.418358)
		(mid 339.83849 -244.488204)
		(end 339.561678 -244.412262)
		(width 0.088646)
		(layer "In6.Cu")
		(net "M_C_CPU0_SB_DQ<0>")
	)
	(arc
		(start 340.501732 -244.412262)
		(mid 340.314534 -244.362119)
		(end 340.127336 -244.412262)
		(width 0.088646)
		(layer "In6.Cu")
		(net "M_C_CPU0_SB_DQ<0>")
	)
	(arc
		(start 339.561678 -244.412262)
		(mid 339.37448 -244.362119)
		(end 339.187282 -244.412262)
		(width 0.088646)
		(layer "In6.Cu")
		(net "M_C_CPU0_SB_DQ<0>")
	)
	(arc
		(start 338.237322 -244.418358)
		(mid 337.95889 -244.488204)
		(end 337.682078 -244.412262)
		(width 0.088646)
		(layer "In6.Cu")
		(net "M_C_CPU0_SB_DQ<0>")
	)
	(arc
		(start 338.622132 -244.412262)
		(mid 338.434934 -244.362119)
		(end 338.247736 -244.412262)
		(width 0.088646)
		(layer "In6.Cu")
		(net "M_C_CPU0_SB_DQ<0>")
	)
	(arc
		(start 343.229184 -243.922804)
		(mid 343.156949 -244.199328)
		(end 342.958674 -244.40515)
		(width 0.088646)
		(layer "In6.Cu")
		(net "M_C_CPU0_SB_DQ<0>")
	)
	(arc
		(start 333.548482 -244.412262)
		(mid 333.26578 -244.488038)
		(end 332.983078 -244.412262)
		(width 0.088646)
		(layer "In6.Cu")
		(net "M_C_CPU0_SB_DQ<0>")
	)
	(arc
		(start 337.682078 -244.412262)
		(mid 337.49488 -244.362119)
		(end 337.307682 -244.412262)
		(width 0.088646)
		(layer "In6.Cu")
		(net "M_C_CPU0_SB_DQ<0>")
	)
	(arc
		(start 336.742278 -244.412262)
		(mid 336.55508 -244.362119)
		(end 336.367882 -244.412262)
		(width 0.088646)
		(layer "In6.Cu")
		(net "M_C_CPU0_SB_DQ<0>")
	)
	(arc
		(start 332.608682 -244.412262)
		(mid 332.391951 -244.484273)
		(end 332.164436 -244.464586)
		(width 0.088646)
		(layer "In6.Cu")
		(net "M_C_CPU0_SB_DQ<0>")
	)
	(arc
		(start 335.802478 -244.412262)
		(mid 335.61528 -244.362119)
		(end 335.428082 -244.412262)
		(width 0.088646)
		(layer "In6.Cu")
		(net "M_C_CPU0_SB_DQ<0>")
	)
	(arc
		(start 334.862678 -244.412262)
		(mid 334.67548 -244.362119)
		(end 334.488282 -244.412262)
		(width 0.088646)
		(layer "In6.Cu")
		(net "M_C_CPU0_SB_DQ<0>")
	)
	(arc
		(start 341.441278 -244.412262)
		(mid 341.25408 -244.362119)
		(end 341.066882 -244.412262)
		(width 0.088646)
		(layer "In6.Cu")
		(net "M_C_CPU0_SB_DQ<0>")
	)
	(arc
		(start 333.922878 -244.412262)
		(mid 333.73568 -244.362119)
		(end 333.548482 -244.412262)
		(width 0.088646)
		(layer "In6.Cu")
		(net "M_C_CPU0_SB_DQ<0>")
	)
	(arc
		(start 342.381078 -244.412262)
		(mid 342.19388 -244.362119)
		(end 342.006682 -244.412262)
		(width 0.088646)
		(layer "In6.Cu")
		(net "M_C_CPU0_SB_DQ<0>")
	)
	(arc
		(start 339.176868 -244.418358)
		(mid 338.89869 -244.488081)
		(end 338.622132 -244.412262)
		(width 0.088646)
		(layer "In6.Cu")
		(net "M_C_CPU0_SB_DQ<0>")
	)
	(arc
		(start 334.488282 -244.412262)
		(mid 334.20558 -244.488038)
		(end 333.922878 -244.412262)
		(width 0.088646)
		(layer "In6.Cu")
		(net "M_C_CPU0_SB_DQ<0>")
	)
	(arc
		(start 335.428082 -244.412262)
		(mid 335.14538 -244.488038)
		(end 334.862678 -244.412262)
		(width 0.088646)
		(layer "In6.Cu")
		(net "M_C_CPU0_SB_DQ<0>")
	)
	(arc
		(start 341.99195 -244.420898)
		(mid 341.715475 -244.488218)
		(end 341.441278 -244.412262)
		(width 0.088646)
		(layer "In6.Cu")
		(net "M_C_CPU0_SB_DQ<0>")
	)
	(arc
		(start 342.946482 -244.412262)
		(mid 342.66378 -244.488038)
		(end 342.381078 -244.412262)
		(width 0.088646)
		(layer "In6.Cu")
		(net "M_C_CPU0_SB_DQ<0>")
	)
	(arc
		(start 332.983078 -244.412262)
		(mid 332.79588 -244.362119)
		(end 332.608682 -244.412262)
		(width 0.088646)
		(layer "In6.Cu")
		(net "M_C_CPU0_SB_DQ<0>")
	)
	(segment
		(start 341.25408 -243.644674)
		(end 341.25408 -243.108988)
		(width 0.20066)
		(layer "F.Cu")
		(net "M_C_CPU0_SB_CS_N<3>")
	)
	(segment
		(start 283.916882 -244.916706)
		(end 282.811982 -244.916706)
		(width 0.20066)
		(layer "F.Cu")
		(net "M_C_CPU0_SB_CS_N<3>")
	)
	(segment
		(start 341.254334 -243.644928)
		(end 341.25408 -243.644674)
		(width 0.20066)
		(layer "F.Cu")
		(net "M_C_CPU0_SB_CS_N<3>")
	)
	(segment
		(start 313.661552 -244.695726)
		(end 313.399932 -244.434106)
		(width 0.18288)
		(layer "In4.Cu")
		(net "M_C_CPU0_SB_CS_N<3>")
	)
	(segment
		(start 312.935112 -244.434106)
		(end 312.673492 -244.695726)
		(width 0.18288)
		(layer "In4.Cu")
		(net "M_C_CPU0_SB_CS_N<3>")
	)
	(segment
		(start 288.598864 -244.843808)
		(end 288.260028 -244.843808)
		(width 0.18288)
		(layer "In4.Cu")
		(net "M_C_CPU0_SB_CS_N<3>")
	)
	(segment
		(start 305.38166 -244.802406)
		(end 305.001422 -244.802406)
		(width 0.18288)
		(layer "In4.Cu")
		(net "M_C_CPU0_SB_CS_N<3>")
	)
	(segment
		(start 333.36103 -244.73662)
		(end 333.36103 -244.758718)
		(width 0.088646)
		(layer "In4.Cu")
		(net "M_C_CPU0_SB_CS_N<3>")
	)
	(segment
		(start 334.958182 -243.598446)
		(end 334.94345 -243.607082)
		(width 0.088646)
		(layer "In4.Cu")
		(net "M_C_CPU0_SB_CS_N<3>")
	)
	(segment
		(start 288.260028 -244.843808)
		(end 287.907984 -244.491764)
		(width 0.18288)
		(layer "In4.Cu")
		(net "M_C_CPU0_SB_CS_N<3>")
	)
	(segment
		(start 336.287364 -243.607082)
		(end 336.272632 -243.598446)
		(width 0.088646)
		(layer "In4.Cu")
		(net "M_C_CPU0_SB_CS_N<3>")
	)
	(segment
		(start 297.445938 -244.810788)
		(end 297.074082 -244.810788)
		(width 0.18288)
		(layer "In4.Cu")
		(net "M_C_CPU0_SB_CS_N<3>")
	)
	(segment
		(start 301.517304 -244.81917)
		(end 301.334424 -245.00205)
		(width 0.18288)
		(layer "In4.Cu")
		(net "M_C_CPU0_SB_CS_N<3>")
	)
	(segment
		(start 297.074082 -244.810788)
		(end 296.755058 -244.491764)
		(width 0.18288)
		(layer "In4.Cu")
		(net "M_C_CPU0_SB_CS_N<3>")
	)
	(segment
		(start 304.310542 -244.491764)
		(end 303.9999 -244.802406)
		(width 0.18288)
		(layer "In4.Cu")
		(net "M_C_CPU0_SB_CS_N<3>")
	)
	(segment
		(start 307.846476 -244.177058)
		(end 307.470302 -244.177058)
		(width 0.18288)
		(layer "In4.Cu")
		(net "M_C_CPU0_SB_CS_N<3>")
	)
	(segment
		(start 309.542942 -244.491764)
		(end 309.228236 -244.177058)
		(width 0.18288)
		(layer "In4.Cu")
		(net "M_C_CPU0_SB_CS_N<3>")
	)
	(segment
		(start 314.946538 -244.695726)
		(end 313.661552 -244.695726)
		(width 0.18288)
		(layer "In4.Cu")
		(net "M_C_CPU0_SB_CS_N<3>")
	)
	(segment
		(start 300.643544 -244.491764)
		(end 297.764962 -244.491764)
		(width 0.18288)
		(layer "In4.Cu")
		(net "M_C_CPU0_SB_CS_N<3>")
	)
	(segment
		(start 297.764962 -244.491764)
		(end 297.445938 -244.810788)
		(width 0.18288)
		(layer "In4.Cu")
		(net "M_C_CPU0_SB_CS_N<3>")
	)
	(segment
		(start 331.85608 -245.302278)
		(end 331.47508 -245.302278)
		(width 0.088646)
		(layer "In4.Cu")
		(net "M_C_CPU0_SB_CS_N<3>")
	)
	(segment
		(start 337.212686 -243.598446)
		(end 337.212432 -243.598446)
		(width 0.088646)
		(layer "In4.Cu")
		(net "M_C_CPU0_SB_CS_N<3>")
	)
	(segment
		(start 285.588456 -244.491764)
		(end 284.341824 -244.491764)
		(width 0.18288)
		(layer "In4.Cu")
		(net "M_C_CPU0_SB_CS_N<3>")
	)
	(segment
		(start 296.383202 -244.491764)
		(end 296.064178 -244.810788)
		(width 0.18288)
		(layer "In4.Cu")
		(net "M_C_CPU0_SB_CS_N<3>")
	)
	(segment
		(start 301.517304 -244.674644)
		(end 301.517304 -244.81917)
		(width 0.18288)
		(layer "In4.Cu")
		(net "M_C_CPU0_SB_CS_N<3>")
	)
	(segment
		(start 296.064178 -244.810788)
		(end 295.692322 -244.810788)
		(width 0.18288)
		(layer "In4.Cu")
		(net "M_C_CPU0_SB_CS_N<3>")
	)
	(segment
		(start 287.907984 -244.491764)
		(end 286.63138 -244.491764)
		(width 0.18288)
		(layer "In4.Cu")
		(net "M_C_CPU0_SB_CS_N<3>")
	)
	(segment
		(start 309.228236 -244.177058)
		(end 308.852062 -244.177058)
		(width 0.18288)
		(layer "In4.Cu")
		(net "M_C_CPU0_SB_CS_N<3>")
	)
	(segment
		(start 338.152232 -243.598446)
		(end 338.151978 -243.598446)
		(width 0.088646)
		(layer "In4.Cu")
		(net "M_C_CPU0_SB_CS_N<3>")
	)
	(segment
		(start 307.470302 -244.177058)
		(end 307.155596 -244.491764)
		(width 0.18288)
		(layer "In4.Cu")
		(net "M_C_CPU0_SB_CS_N<3>")
	)
	(segment
		(start 290.332668 -244.491764)
		(end 289.980624 -244.843808)
		(width 0.18288)
		(layer "In4.Cu")
		(net "M_C_CPU0_SB_CS_N<3>")
	)
	(segment
		(start 294.2463 -244.491764)
		(end 293.901876 -244.836188)
		(width 0.18288)
		(layer "In4.Cu")
		(net "M_C_CPU0_SB_CS_N<3>")
	)
	(segment
		(start 293.901876 -244.836188)
		(end 293.55542 -244.836188)
		(width 0.18288)
		(layer "In4.Cu")
		(net "M_C_CPU0_SB_CS_N<3>")
	)
	(segment
		(start 307.155596 -244.491764)
		(end 305.692302 -244.491764)
		(width 0.18288)
		(layer "In4.Cu")
		(net "M_C_CPU0_SB_CS_N<3>")
	)
	(segment
		(start 331.192632 -245.01983)
		(end 331.004418 -245.01983)
		(width 0.088646)
		(layer "In4.Cu")
		(net "M_C_CPU0_SB_CS_N<3>")
	)
	(segment
		(start 340.204044 -243.478304)
		(end 340.116668 -243.42725)
		(width 0.088646)
		(layer "In4.Cu")
		(net "M_C_CPU0_SB_CS_N<3>")
	)
	(segment
		(start 313.399932 -244.434106)
		(end 312.935112 -244.434106)
		(width 0.18288)
		(layer "In4.Cu")
		(net "M_C_CPU0_SB_CS_N<3>")
	)
	(segment
		(start 286.63138 -244.491764)
		(end 286.279336 -244.843808)
		(width 0.18288)
		(layer "In4.Cu")
		(net "M_C_CPU0_SB_CS_N<3>")
	)
	(segment
		(start 286.279336 -244.843808)
		(end 285.9405 -244.843808)
		(width 0.18288)
		(layer "In4.Cu")
		(net "M_C_CPU0_SB_CS_N<3>")
	)
	(segment
		(start 288.950908 -244.491764)
		(end 288.598864 -244.843808)
		(width 0.18288)
		(layer "In4.Cu")
		(net "M_C_CPU0_SB_CS_N<3>")
	)
	(segment
		(start 293.55542 -244.836188)
		(end 293.210996 -244.491764)
		(width 0.18288)
		(layer "In4.Cu")
		(net "M_C_CPU0_SB_CS_N<3>")
	)
	(segment
		(start 341.25408 -243.108988)
		(end 340.985602 -243.377466)
		(width 0.088646)
		(layer "In4.Cu")
		(net "M_C_CPU0_SB_CS_N<3>")
	)
	(segment
		(start 289.641788 -244.843808)
		(end 289.289744 -244.491764)
		(width 0.18288)
		(layer "In4.Cu")
		(net "M_C_CPU0_SB_CS_N<3>")
	)
	(segment
		(start 300.826424 -244.674644)
		(end 300.643544 -244.491764)
		(width 0.18288)
		(layer "In4.Cu")
		(net "M_C_CPU0_SB_CS_N<3>")
	)
	(segment
		(start 296.755058 -244.491764)
		(end 296.383202 -244.491764)
		(width 0.18288)
		(layer "In4.Cu")
		(net "M_C_CPU0_SB_CS_N<3>")
	)
	(segment
		(start 338.621878 -243.433346)
		(end 338.336128 -243.598192)
		(width 0.088646)
		(layer "In4.Cu")
		(net "M_C_CPU0_SB_CS_N<3>")
	)
	(segment
		(start 331.004418 -245.01983)
		(end 315.270642 -245.01983)
		(width 0.18288)
		(layer "In4.Cu")
		(net "M_C_CPU0_SB_CS_N<3>")
	)
	(segment
		(start 335.898236 -243.598446)
		(end 335.887822 -243.604542)
		(width 0.088646)
		(layer "In4.Cu")
		(net "M_C_CPU0_SB_CS_N<3>")
	)
	(segment
		(start 301.009304 -245.00205)
		(end 300.826424 -244.81917)
		(width 0.18288)
		(layer "In4.Cu")
		(net "M_C_CPU0_SB_CS_N<3>")
	)
	(segment
		(start 332.528164 -245.234968)
		(end 332.513432 -245.226332)
		(width 0.088646)
		(layer "In4.Cu")
		(net "M_C_CPU0_SB_CS_N<3>")
	)
	(segment
		(start 333.548482 -244.412262)
		(end 333.539592 -244.417342)
		(width 0.088646)
		(layer "In4.Cu")
		(net "M_C_CPU0_SB_CS_N<3>")
	)
	(segment
		(start 289.980624 -244.843808)
		(end 289.641788 -244.843808)
		(width 0.18288)
		(layer "In4.Cu")
		(net "M_C_CPU0_SB_CS_N<3>")
	)
	(segment
		(start 300.826424 -244.81917)
		(end 300.826424 -244.674644)
		(width 0.18288)
		(layer "In4.Cu")
		(net "M_C_CPU0_SB_CS_N<3>")
	)
	(segment
		(start 303.619662 -244.802406)
		(end 303.30902 -244.491764)
		(width 0.18288)
		(layer "In4.Cu")
		(net "M_C_CPU0_SB_CS_N<3>")
	)
	(segment
		(start 308.852062 -244.177058)
		(end 308.537356 -244.491764)
		(width 0.18288)
		(layer "In4.Cu")
		(net "M_C_CPU0_SB_CS_N<3>")
	)
	(segment
		(start 304.69078 -244.491764)
		(end 304.310542 -244.491764)
		(width 0.18288)
		(layer "In4.Cu")
		(net "M_C_CPU0_SB_CS_N<3>")
	)
	(segment
		(start 308.537356 -244.491764)
		(end 308.161182 -244.491764)
		(width 0.18288)
		(layer "In4.Cu")
		(net "M_C_CPU0_SB_CS_N<3>")
	)
	(segment
		(start 312.673492 -244.695726)
		(end 310.552592 -244.695726)
		(width 0.18288)
		(layer "In4.Cu")
		(net "M_C_CPU0_SB_CS_N<3>")
	)
	(segment
		(start 305.692302 -244.491764)
		(end 305.38166 -244.802406)
		(width 0.18288)
		(layer "In4.Cu")
		(net "M_C_CPU0_SB_CS_N<3>")
	)
	(segment
		(start 301.334424 -245.00205)
		(end 301.009304 -245.00205)
		(width 0.18288)
		(layer "In4.Cu")
		(net "M_C_CPU0_SB_CS_N<3>")
	)
	(segment
		(start 310.34863 -244.491764)
		(end 309.542942 -244.491764)
		(width 0.18288)
		(layer "In4.Cu")
		(net "M_C_CPU0_SB_CS_N<3>")
	)
	(segment
		(start 293.210996 -244.491764)
		(end 290.332668 -244.491764)
		(width 0.18288)
		(layer "In4.Cu")
		(net "M_C_CPU0_SB_CS_N<3>")
	)
	(segment
		(start 310.552592 -244.695726)
		(end 310.34863 -244.491764)
		(width 0.18288)
		(layer "In4.Cu")
		(net "M_C_CPU0_SB_CS_N<3>")
	)
	(segment
		(start 308.161182 -244.491764)
		(end 307.846476 -244.177058)
		(width 0.18288)
		(layer "In4.Cu")
		(net "M_C_CPU0_SB_CS_N<3>")
	)
	(segment
		(start 303.9999 -244.802406)
		(end 303.619662 -244.802406)
		(width 0.18288)
		(layer "In4.Cu")
		(net "M_C_CPU0_SB_CS_N<3>")
	)
	(segment
		(start 303.30902 -244.491764)
		(end 301.700184 -244.491764)
		(width 0.18288)
		(layer "In4.Cu")
		(net "M_C_CPU0_SB_CS_N<3>")
	)
	(segment
		(start 301.700184 -244.491764)
		(end 301.517304 -244.674644)
		(width 0.18288)
		(layer "In4.Cu")
		(net "M_C_CPU0_SB_CS_N<3>")
	)
	(segment
		(start 285.9405 -244.843808)
		(end 285.588456 -244.491764)
		(width 0.18288)
		(layer "In4.Cu")
		(net "M_C_CPU0_SB_CS_N<3>")
	)
	(segment
		(start 295.692322 -244.810788)
		(end 295.373298 -244.491764)
		(width 0.18288)
		(layer "In4.Cu")
		(net "M_C_CPU0_SB_CS_N<3>")
	)
	(segment
		(start 334.018382 -243.598446)
		(end 334.009492 -243.603526)
		(width 0.088646)
		(layer "In4.Cu")
		(net "M_C_CPU0_SB_CS_N<3>")
	)
	(segment
		(start 315.270642 -245.01983)
		(end 314.946538 -244.695726)
		(width 0.18288)
		(layer "In4.Cu")
		(net "M_C_CPU0_SB_CS_N<3>")
	)
	(segment
		(start 284.341824 -244.491764)
		(end 283.916882 -244.916706)
		(width 0.18288)
		(layer "In4.Cu")
		(net "M_C_CPU0_SB_CS_N<3>")
	)
	(segment
		(start 333.83093 -243.922804)
		(end 333.83093 -243.93271)
		(width 0.088646)
		(layer "In4.Cu")
		(net "M_C_CPU0_SB_CS_N<3>")
	)
	(segment
		(start 289.289744 -244.491764)
		(end 288.950908 -244.491764)
		(width 0.18288)
		(layer "In4.Cu")
		(net "M_C_CPU0_SB_CS_N<3>")
	)
	(segment
		(start 339.187536 -243.433346)
		(end 339.187282 -243.433346)
		(width 0.088646)
		(layer "In4.Cu")
		(net "M_C_CPU0_SB_CS_N<3>")
	)
	(segment
		(start 305.001422 -244.802406)
		(end 304.69078 -244.491764)
		(width 0.18288)
		(layer "In4.Cu")
		(net "M_C_CPU0_SB_CS_N<3>")
	)
	(segment
		(start 331.47508 -245.302278)
		(end 331.192632 -245.01983)
		(width 0.088646)
		(layer "In4.Cu")
		(net "M_C_CPU0_SB_CS_N<3>")
	)
	(segment
		(start 295.373298 -244.491764)
		(end 294.2463 -244.491764)
		(width 0.18288)
		(layer "In4.Cu")
		(net "M_C_CPU0_SB_CS_N<3>")
	)
	(arc
		(start 332.513432 -245.226332)
		(mid 332.326234 -245.176189)
		(end 332.139036 -245.226332)
		(width 0.088646)
		(layer "In4.Cu")
		(net "M_C_CPU0_SB_CS_N<3>")
	)
	(arc
		(start 340.985602 -243.377466)
		(mid 340.721941 -243.537028)
		(end 340.414356 -243.556028)
		(width 0.088646)
		(layer "In4.Cu")
		(net "M_C_CPU0_SB_CS_N<3>")
	)
	(arc
		(start 339.561932 -243.433346)
		(mid 339.374734 -243.483523)
		(end 339.187536 -243.433346)
		(width 0.088646)
		(layer "In4.Cu")
		(net "M_C_CPU0_SB_CS_N<3>")
	)
	(arc
		(start 333.36103 -244.758718)
		(mid 333.280119 -245.028846)
		(end 333.078836 -245.226332)
		(width 0.088646)
		(layer "In4.Cu")
		(net "M_C_CPU0_SB_CS_N<3>")
	)
	(arc
		(start 333.83093 -243.93271)
		(mid 333.752819 -244.209659)
		(end 333.548482 -244.412262)
		(width 0.088646)
		(layer "In4.Cu")
		(net "M_C_CPU0_SB_CS_N<3>")
	)
	(arc
		(start 337.777836 -243.598446)
		(mid 337.495278 -243.674095)
		(end 337.212686 -243.598446)
		(width 0.088646)
		(layer "In4.Cu")
		(net "M_C_CPU0_SB_CS_N<3>")
	)
	(arc
		(start 338.151978 -243.598446)
		(mid 337.964924 -243.548396)
		(end 337.777836 -243.598446)
		(width 0.088646)
		(layer "In4.Cu")
		(net "M_C_CPU0_SB_CS_N<3>")
	)
	(arc
		(start 339.187282 -243.433346)
		(mid 338.90458 -243.35757)
		(end 338.621878 -243.433346)
		(width 0.088646)
		(layer "In4.Cu")
		(net "M_C_CPU0_SB_CS_N<3>")
	)
	(arc
		(start 336.272632 -243.598446)
		(mid 336.085434 -243.548303)
		(end 335.898236 -243.598446)
		(width 0.088646)
		(layer "In4.Cu")
		(net "M_C_CPU0_SB_CS_N<3>")
	)
	(arc
		(start 334.009492 -243.603526)
		(mid 333.878578 -243.739886)
		(end 333.83093 -243.922804)
		(width 0.088646)
		(layer "In4.Cu")
		(net "M_C_CPU0_SB_CS_N<3>")
	)
	(arc
		(start 337.212432 -243.598446)
		(mid 337.025234 -243.548303)
		(end 336.838036 -243.598446)
		(width 0.088646)
		(layer "In4.Cu")
		(net "M_C_CPU0_SB_CS_N<3>")
	)
	(arc
		(start 332.139036 -245.226332)
		(mid 332.002563 -245.282966)
		(end 331.85608 -245.302278)
		(width 0.088646)
		(layer "In4.Cu")
		(net "M_C_CPU0_SB_CS_N<3>")
	)
	(arc
		(start 335.887822 -243.604542)
		(mid 335.60939 -243.674388)
		(end 335.332578 -243.598446)
		(width 0.088646)
		(layer "In4.Cu")
		(net "M_C_CPU0_SB_CS_N<3>")
	)
	(arc
		(start 334.392778 -243.598446)
		(mid 334.20558 -243.548303)
		(end 334.018382 -243.598446)
		(width 0.088646)
		(layer "In4.Cu")
		(net "M_C_CPU0_SB_CS_N<3>")
	)
	(arc
		(start 333.078836 -245.226332)
		(mid 332.804607 -245.302257)
		(end 332.528164 -245.234968)
		(width 0.088646)
		(layer "In4.Cu")
		(net "M_C_CPU0_SB_CS_N<3>")
	)
	(arc
		(start 333.539592 -244.417342)
		(mid 333.408678 -244.553702)
		(end 333.36103 -244.73662)
		(width 0.088646)
		(layer "In4.Cu")
		(net "M_C_CPU0_SB_CS_N<3>")
	)
	(arc
		(start 334.94345 -243.607082)
		(mid 334.666975 -243.674402)
		(end 334.392778 -243.598446)
		(width 0.088646)
		(layer "In4.Cu")
		(net "M_C_CPU0_SB_CS_N<3>")
	)
	(arc
		(start 336.838036 -243.598446)
		(mid 336.563837 -243.674281)
		(end 336.287364 -243.607082)
		(width 0.088646)
		(layer "In4.Cu")
		(net "M_C_CPU0_SB_CS_N<3>")
	)
	(arc
		(start 340.116668 -243.42725)
		(mid 339.83849 -243.357527)
		(end 339.561932 -243.433346)
		(width 0.088646)
		(layer "In4.Cu")
		(net "M_C_CPU0_SB_CS_N<3>")
	)
	(arc
		(start 340.414356 -243.556028)
		(mid 340.305797 -243.526373)
		(end 340.204044 -243.478304)
		(width 0.088646)
		(layer "In4.Cu")
		(net "M_C_CPU0_SB_CS_N<3>")
	)
	(arc
		(start 335.332578 -243.598446)
		(mid 335.14538 -243.548303)
		(end 334.958182 -243.598446)
		(width 0.088646)
		(layer "In4.Cu")
		(net "M_C_CPU0_SB_CS_N<3>")
	)
	(arc
		(start 338.336128 -243.598192)
		(mid 338.244209 -243.622991)
		(end 338.152232 -243.598446)
		(width 0.088646)
		(layer "In4.Cu")
		(net "M_C_CPU0_SB_CS_N<3>")
	)
	(segment
		(start 341.72398 -244.458744)
		(end 341.724234 -244.45849)
		(width 0.20066)
		(layer "F.Cu")
		(net "M_C_CPU0_SB_CS_N<2>")
	)
	(segment
		(start 279.816814 -245.76659)
		(end 278.711914 -245.76659)
		(width 0.20066)
		(layer "F.Cu")
		(net "M_C_CPU0_SB_CS_N<2>")
	)
	(segment
		(start 341.724234 -244.45849)
		(end 341.724234 -243.922804)
		(width 0.20066)
		(layer "F.Cu")
		(net "M_C_CPU0_SB_CS_N<2>")
	)
	(segment
		(start 331.004418 -246.01551)
		(end 314.60821 -246.01551)
		(width 0.18288)
		(layer "In4.Cu")
		(net "M_C_CPU0_SB_CS_N<2>")
	)
	(segment
		(start 341.724234 -243.922804)
		(end 341.000842 -244.230144)
		(width 0.088646)
		(layer "In4.Cu")
		(net "M_C_CPU0_SB_CS_N<2>")
	)
	(segment
		(start 338.247736 -244.412262)
		(end 338.247482 -244.412262)
		(width 0.088646)
		(layer "In4.Cu")
		(net "M_C_CPU0_SB_CS_N<2>")
	)
	(segment
		(start 314.60821 -246.01551)
		(end 314.431934 -246.191786)
		(width 0.18288)
		(layer "In4.Cu")
		(net "M_C_CPU0_SB_CS_N<2>")
	)
	(segment
		(start 336.367882 -244.412262)
		(end 336.35315 -244.420898)
		(width 0.088646)
		(layer "In4.Cu")
		(net "M_C_CPU0_SB_CS_N<2>")
	)
	(segment
		(start 286.360362 -246.191786)
		(end 286.010096 -245.84152)
		(width 0.18288)
		(layer "In4.Cu")
		(net "M_C_CPU0_SB_CS_N<2>")
	)
	(segment
		(start 334.488282 -244.412262)
		(end 334.479392 -244.417342)
		(width 0.088646)
		(layer "In4.Cu")
		(net "M_C_CPU0_SB_CS_N<2>")
	)
	(segment
		(start 282.913328 -246.191786)
		(end 282.742386 -246.362728)
		(width 0.18288)
		(layer "In4.Cu")
		(net "M_C_CPU0_SB_CS_N<2>")
	)
	(segment
		(start 337.307682 -244.412262)
		(end 337.29295 -244.420898)
		(width 0.088646)
		(layer "In4.Cu")
		(net "M_C_CPU0_SB_CS_N<2>")
	)
	(segment
		(start 280.412952 -246.362728)
		(end 279.816814 -245.76659)
		(width 0.18288)
		(layer "In4.Cu")
		(net "M_C_CPU0_SB_CS_N<2>")
	)
	(segment
		(start 341.000842 -244.230144)
		(end 340.971632 -244.247162)
		(width 0.088646)
		(layer "In4.Cu")
		(net "M_C_CPU0_SB_CS_N<2>")
	)
	(segment
		(start 339.092286 -244.247162)
		(end 339.092032 -244.247162)
		(width 0.088646)
		(layer "In4.Cu")
		(net "M_C_CPU0_SB_CS_N<2>")
	)
	(segment
		(start 334.30083 -244.73662)
		(end 334.30083 -244.758718)
		(width 0.088646)
		(layer "In4.Cu")
		(net "M_C_CPU0_SB_CS_N<2>")
	)
	(segment
		(start 334.018636 -245.226332)
		(end 334.009746 -245.231412)
		(width 0.088646)
		(layer "In4.Cu")
		(net "M_C_CPU0_SB_CS_N<2>")
	)
	(segment
		(start 333.831184 -245.55069)
		(end 333.831184 -245.560596)
		(width 0.088646)
		(layer "In4.Cu")
		(net "M_C_CPU0_SB_CS_N<2>")
	)
	(segment
		(start 284.25267 -246.191786)
		(end 282.913328 -246.191786)
		(width 0.18288)
		(layer "In4.Cu")
		(net "M_C_CPU0_SB_CS_N<2>")
	)
	(segment
		(start 314.431934 -246.191786)
		(end 286.360362 -246.191786)
		(width 0.18288)
		(layer "In4.Cu")
		(net "M_C_CPU0_SB_CS_N<2>")
	)
	(segment
		(start 338.53374 -244.247162)
		(end 338.247736 -244.412262)
		(width 0.088646)
		(layer "In4.Cu")
		(net "M_C_CPU0_SB_CS_N<2>")
	)
	(segment
		(start 286.010096 -245.84152)
		(end 284.602936 -245.84152)
		(width 0.18288)
		(layer "In4.Cu")
		(net "M_C_CPU0_SB_CS_N<2>")
	)
	(segment
		(start 340.031832 -244.247162)
		(end 340.031578 -244.247162)
		(width 0.088646)
		(layer "In4.Cu")
		(net "M_C_CPU0_SB_CS_N<2>")
	)
	(segment
		(start 331.951584 -246.01551)
		(end 331.004418 -246.01551)
		(width 0.088646)
		(layer "In4.Cu")
		(net "M_C_CPU0_SB_CS_N<2>")
	)
	(segment
		(start 282.742386 -246.362728)
		(end 280.412952 -246.362728)
		(width 0.18288)
		(layer "In4.Cu")
		(net "M_C_CPU0_SB_CS_N<2>")
	)
	(segment
		(start 284.602936 -245.84152)
		(end 284.25267 -246.191786)
		(width 0.18288)
		(layer "In4.Cu")
		(net "M_C_CPU0_SB_CS_N<2>")
	)
	(arc
		(start 334.30083 -244.758718)
		(mid 334.219919 -245.028846)
		(end 334.018636 -245.226332)
		(width 0.088646)
		(layer "In4.Cu")
		(net "M_C_CPU0_SB_CS_N<2>")
	)
	(arc
		(start 337.682078 -244.412262)
		(mid 337.49488 -244.362119)
		(end 337.307682 -244.412262)
		(width 0.088646)
		(layer "In4.Cu")
		(net "M_C_CPU0_SB_CS_N<2>")
	)
	(arc
		(start 335.428082 -244.412262)
		(mid 335.14538 -244.488038)
		(end 334.862678 -244.412262)
		(width 0.088646)
		(layer "In4.Cu")
		(net "M_C_CPU0_SB_CS_N<2>")
	)
	(arc
		(start 339.657436 -244.247162)
		(mid 339.374878 -244.171513)
		(end 339.092286 -244.247162)
		(width 0.088646)
		(layer "In4.Cu")
		(net "M_C_CPU0_SB_CS_N<2>")
	)
	(arc
		(start 340.971632 -244.247162)
		(mid 340.784434 -244.297305)
		(end 340.597236 -244.247162)
		(width 0.088646)
		(layer "In4.Cu")
		(net "M_C_CPU0_SB_CS_N<2>")
	)
	(arc
		(start 334.479392 -244.417342)
		(mid 334.348478 -244.553702)
		(end 334.30083 -244.73662)
		(width 0.088646)
		(layer "In4.Cu")
		(net "M_C_CPU0_SB_CS_N<2>")
	)
	(arc
		(start 334.009746 -245.231412)
		(mid 333.878832 -245.367772)
		(end 333.831184 -245.55069)
		(width 0.088646)
		(layer "In4.Cu")
		(net "M_C_CPU0_SB_CS_N<2>")
	)
	(arc
		(start 332.983332 -246.040148)
		(mid 332.796134 -245.990005)
		(end 332.608936 -246.040148)
		(width 0.088646)
		(layer "In4.Cu")
		(net "M_C_CPU0_SB_CS_N<2>")
	)
	(arc
		(start 338.247482 -244.412262)
		(mid 337.96478 -244.488038)
		(end 337.682078 -244.412262)
		(width 0.088646)
		(layer "In4.Cu")
		(net "M_C_CPU0_SB_CS_N<2>")
	)
	(arc
		(start 340.031578 -244.247162)
		(mid 339.844524 -244.297246)
		(end 339.657436 -244.247162)
		(width 0.088646)
		(layer "In4.Cu")
		(net "M_C_CPU0_SB_CS_N<2>")
	)
	(arc
		(start 337.29295 -244.420898)
		(mid 337.016475 -244.488218)
		(end 336.742278 -244.412262)
		(width 0.088646)
		(layer "In4.Cu")
		(net "M_C_CPU0_SB_CS_N<2>")
	)
	(arc
		(start 332.043532 -246.040148)
		(mid 331.99918 -246.021777)
		(end 331.951584 -246.01551)
		(width 0.088646)
		(layer "In4.Cu")
		(net "M_C_CPU0_SB_CS_N<2>")
	)
	(arc
		(start 333.548736 -246.040148)
		(mid 333.266034 -246.115924)
		(end 332.983332 -246.040148)
		(width 0.088646)
		(layer "In4.Cu")
		(net "M_C_CPU0_SB_CS_N<2>")
	)
	(arc
		(start 332.608936 -246.040148)
		(mid 332.326234 -246.115924)
		(end 332.043532 -246.040148)
		(width 0.088646)
		(layer "In4.Cu")
		(net "M_C_CPU0_SB_CS_N<2>")
	)
	(arc
		(start 336.35315 -244.420898)
		(mid 336.076675 -244.488218)
		(end 335.802478 -244.412262)
		(width 0.088646)
		(layer "In4.Cu")
		(net "M_C_CPU0_SB_CS_N<2>")
	)
	(arc
		(start 335.802478 -244.412262)
		(mid 335.61528 -244.362119)
		(end 335.428082 -244.412262)
		(width 0.088646)
		(layer "In4.Cu")
		(net "M_C_CPU0_SB_CS_N<2>")
	)
	(arc
		(start 334.862678 -244.412262)
		(mid 334.67548 -244.362119)
		(end 334.488282 -244.412262)
		(width 0.088646)
		(layer "In4.Cu")
		(net "M_C_CPU0_SB_CS_N<2>")
	)
	(arc
		(start 339.092032 -244.247162)
		(mid 338.904834 -244.297305)
		(end 338.717636 -244.247162)
		(width 0.088646)
		(layer "In4.Cu")
		(net "M_C_CPU0_SB_CS_N<2>")
	)
	(arc
		(start 333.831184 -245.560596)
		(mid 333.753073 -245.837545)
		(end 333.548736 -246.040148)
		(width 0.088646)
		(layer "In4.Cu")
		(net "M_C_CPU0_SB_CS_N<2>")
	)
	(arc
		(start 340.597236 -244.247162)
		(mid 340.314534 -244.17142)
		(end 340.031832 -244.247162)
		(width 0.088646)
		(layer "In4.Cu")
		(net "M_C_CPU0_SB_CS_N<2>")
	)
	(arc
		(start 338.717636 -244.247162)
		(mid 338.625688 -244.222525)
		(end 338.53374 -244.247162)
		(width 0.088646)
		(layer "In4.Cu")
		(net "M_C_CPU0_SB_CS_N<2>")
	)
	(arc
		(start 336.742278 -244.412262)
		(mid 336.55508 -244.362119)
		(end 336.367882 -244.412262)
		(width 0.088646)
		(layer "In4.Cu")
		(net "M_C_CPU0_SB_CS_N<2>")
	)
	(segment
		(start 340.31428 -243.644674)
		(end 340.31428 -243.108988)
		(width 0.20066)
		(layer "F.Cu")
		(net "M_C_CPU0_SB_CS_N<1>")
	)
	(segment
		(start 276.373082 -244.916706)
		(end 275.268182 -244.916706)
		(width 0.20066)
		(layer "F.Cu")
		(net "M_C_CPU0_SB_CS_N<1>")
	)
	(segment
		(start 340.314534 -243.644928)
		(end 340.31428 -243.644674)
		(width 0.20066)
		(layer "F.Cu")
		(net "M_C_CPU0_SB_CS_N<1>")
	)
	(segment
		(start 278.235918 -244.611144)
		(end 278.235918 -243.824506)
		(width 0.18288)
		(layer "In4.Cu")
		(net "M_C_CPU0_SB_CS_N<1>")
	)
	(segment
		(start 315.631068 -243.430298)
		(end 313.825128 -243.430298)
		(width 0.18288)
		(layer "In4.Cu")
		(net "M_C_CPU0_SB_CS_N<1>")
	)
	(segment
		(start 290.961572 -243.641626)
		(end 290.660328 -243.340382)
		(width 0.18288)
		(layer "In4.Cu")
		(net "M_C_CPU0_SB_CS_N<1>")
	)
	(segment
		(start 282.128722 -243.641626)
		(end 279.109678 -243.641626)
		(width 0.18288)
		(layer "In4.Cu")
		(net "M_C_CPU0_SB_CS_N<1>")
	)
	(segment
		(start 300.797214 -243.64061)
		(end 300.587664 -243.43106)
		(width 0.18288)
		(layer "In4.Cu")
		(net "M_C_CPU0_SB_CS_N<1>")
	)
	(segment
		(start 306.266342 -243.640864)
		(end 304.936144 -243.640864)
		(width 0.18288)
		(layer "In4.Cu")
		(net "M_C_CPU0_SB_CS_N<1>")
	)
	(segment
		(start 278.926798 -244.611144)
		(end 278.743918 -244.794024)
		(width 0.18288)
		(layer "In4.Cu")
		(net "M_C_CPU0_SB_CS_N<1>")
	)
	(segment
		(start 333.937864 -243.42471)
		(end 333.923132 -243.433346)
		(width 0.088646)
		(layer "In4.Cu")
		(net "M_C_CPU0_SB_CS_N<1>")
	)
	(segment
		(start 284.779466 -243.458746)
		(end 284.596586 -243.641626)
		(width 0.18288)
		(layer "In4.Cu")
		(net "M_C_CPU0_SB_CS_N<1>")
	)
	(segment
		(start 333.461868 -244.242082)
		(end 333.452978 -244.247162)
		(width 0.088646)
		(layer "In4.Cu")
		(net "M_C_CPU0_SB_CS_N<1>")
	)
	(segment
		(start 304.936144 -243.640864)
		(end 304.935382 -243.641626)
		(width 0.18288)
		(layer "In4.Cu")
		(net "M_C_CPU0_SB_CS_N<1>")
	)
	(segment
		(start 285.470346 -243.458746)
		(end 285.470346 -243.220494)
		(width 0.18288)
		(layer "In4.Cu")
		(net "M_C_CPU0_SB_CS_N<1>")
	)
	(segment
		(start 331.85608 -245.112032)
		(end 331.766164 -245.112032)
		(width 0.088646)
		(layer "In4.Cu")
		(net "M_C_CPU0_SB_CS_N<1>")
	)
	(segment
		(start 285.653226 -243.641626)
		(end 285.470346 -243.458746)
		(width 0.18288)
		(layer "In4.Cu")
		(net "M_C_CPU0_SB_CS_N<1>")
	)
	(segment
		(start 282.819602 -244.835934)
		(end 282.494482 -244.835934)
		(width 0.18288)
		(layer "In4.Cu")
		(net "M_C_CPU0_SB_CS_N<1>")
	)
	(segment
		(start 284.779466 -243.220494)
		(end 284.779466 -243.458746)
		(width 0.18288)
		(layer "In4.Cu")
		(net "M_C_CPU0_SB_CS_N<1>")
	)
	(segment
		(start 278.053038 -243.641626)
		(end 277.648162 -243.641626)
		(width 0.18288)
		(layer "In4.Cu")
		(net "M_C_CPU0_SB_CS_N<1>")
	)
	(segment
		(start 283.185362 -243.641626)
		(end 283.002482 -243.824506)
		(width 0.18288)
		(layer "In4.Cu")
		(net "M_C_CPU0_SB_CS_N<1>")
	)
	(segment
		(start 283.002482 -243.824506)
		(end 283.002482 -244.653054)
		(width 0.18288)
		(layer "In4.Cu")
		(net "M_C_CPU0_SB_CS_N<1>")
	)
	(segment
		(start 333.17053 -244.726714)
		(end 333.17053 -244.73662)
		(width 0.088646)
		(layer "In4.Cu")
		(net "M_C_CPU0_SB_CS_N<1>")
	)
	(segment
		(start 284.596586 -243.641626)
		(end 283.185362 -243.641626)
		(width 0.18288)
		(layer "In4.Cu")
		(net "M_C_CPU0_SB_CS_N<1>")
	)
	(segment
		(start 285.287466 -243.037614)
		(end 284.962346 -243.037614)
		(width 0.18288)
		(layer "In4.Cu")
		(net "M_C_CPU0_SB_CS_N<1>")
	)
	(segment
		(start 332.608682 -245.060978)
		(end 332.59395 -245.052342)
		(width 0.088646)
		(layer "In4.Cu")
		(net "M_C_CPU0_SB_CS_N<1>")
	)
	(segment
		(start 285.470346 -243.220494)
		(end 285.287466 -243.037614)
		(width 0.18288)
		(layer "In4.Cu")
		(net "M_C_CPU0_SB_CS_N<1>")
	)
	(segment
		(start 290.660328 -243.340382)
		(end 289.050222 -243.340382)
		(width 0.18288)
		(layer "In4.Cu")
		(net "M_C_CPU0_SB_CS_N<1>")
	)
	(segment
		(start 340.31428 -243.108988)
		(end 339.609684 -242.70208)
		(width 0.088646)
		(layer "In4.Cu")
		(net "M_C_CPU0_SB_CS_N<1>")
	)
	(segment
		(start 301.124112 -243.641626)
		(end 301.123096 -243.64061)
		(width 0.18288)
		(layer "In4.Cu")
		(net "M_C_CPU0_SB_CS_N<1>")
	)
	(segment
		(start 279.109678 -243.641626)
		(end 278.926798 -243.824506)
		(width 0.18288)
		(layer "In4.Cu")
		(net "M_C_CPU0_SB_CS_N<1>")
	)
	(segment
		(start 278.926798 -243.824506)
		(end 278.926798 -244.611144)
		(width 0.18288)
		(layer "In4.Cu")
		(net "M_C_CPU0_SB_CS_N<1>")
	)
	(segment
		(start 331.766164 -245.112032)
		(end 331.176122 -244.52199)
		(width 0.088646)
		(layer "In4.Cu")
		(net "M_C_CPU0_SB_CS_N<1>")
	)
	(segment
		(start 278.743918 -244.794024)
		(end 278.418798 -244.794024)
		(width 0.18288)
		(layer "In4.Cu")
		(net "M_C_CPU0_SB_CS_N<1>")
	)
	(segment
		(start 331.004418 -244.52199)
		(end 316.72276 -244.52199)
		(width 0.18288)
		(layer "In4.Cu")
		(net "M_C_CPU0_SB_CS_N<1>")
	)
	(segment
		(start 332.991968 -245.055898)
		(end 332.983078 -245.060978)
		(width 0.088646)
		(layer "In4.Cu")
		(net "M_C_CPU0_SB_CS_N<1>")
	)
	(segment
		(start 334.877664 -243.42471)
		(end 334.862932 -243.433346)
		(width 0.088646)
		(layer "In4.Cu")
		(net "M_C_CPU0_SB_CS_N<1>")
	)
	(segment
		(start 337.307936 -243.433346)
		(end 337.307682 -243.433346)
		(width 0.088646)
		(layer "In4.Cu")
		(net "M_C_CPU0_SB_CS_N<1>")
	)
	(segment
		(start 339.139784 -242.70208)
		(end 338.996528 -242.78463)
		(width 0.088646)
		(layer "In4.Cu")
		(net "M_C_CPU0_SB_CS_N<1>")
	)
	(segment
		(start 299.642276 -243.641626)
		(end 290.961572 -243.641626)
		(width 0.18288)
		(layer "In4.Cu")
		(net "M_C_CPU0_SB_CS_N<1>")
	)
	(segment
		(start 313.825128 -243.430298)
		(end 313.6138 -243.641626)
		(width 0.18288)
		(layer "In4.Cu")
		(net "M_C_CPU0_SB_CS_N<1>")
	)
	(segment
		(start 304.935382 -243.641626)
		(end 301.124112 -243.641626)
		(width 0.18288)
		(layer "In4.Cu")
		(net "M_C_CPU0_SB_CS_N<1>")
	)
	(segment
		(start 333.923132 -243.433346)
		(end 333.917036 -243.436902)
		(width 0.088646)
		(layer "In4.Cu")
		(net "M_C_CPU0_SB_CS_N<1>")
	)
	(segment
		(start 313.6138 -243.641626)
		(end 309.491126 -243.641626)
		(width 0.18288)
		(layer "In4.Cu")
		(net "M_C_CPU0_SB_CS_N<1>")
	)
	(segment
		(start 283.002482 -244.653054)
		(end 282.819602 -244.835934)
		(width 0.18288)
		(layer "In4.Cu")
		(net "M_C_CPU0_SB_CS_N<1>")
	)
	(segment
		(start 338.247482 -242.78463)
		(end 337.961732 -242.94973)
		(width 0.088646)
		(layer "In4.Cu")
		(net "M_C_CPU0_SB_CS_N<1>")
	)
	(segment
		(start 337.307682 -243.433346)
		(end 337.29295 -243.42471)
		(width 0.088646)
		(layer "In4.Cu")
		(net "M_C_CPU0_SB_CS_N<1>")
	)
	(segment
		(start 300.587664 -243.43106)
		(end 299.852842 -243.43106)
		(width 0.18288)
		(layer "In4.Cu")
		(net "M_C_CPU0_SB_CS_N<1>")
	)
	(segment
		(start 282.494482 -244.835934)
		(end 282.311602 -244.653054)
		(width 0.18288)
		(layer "In4.Cu")
		(net "M_C_CPU0_SB_CS_N<1>")
	)
	(segment
		(start 282.311602 -244.653054)
		(end 282.311602 -243.824506)
		(width 0.18288)
		(layer "In4.Cu")
		(net "M_C_CPU0_SB_CS_N<1>")
	)
	(segment
		(start 306.38877 -243.518436)
		(end 306.266342 -243.640864)
		(width 0.18288)
		(layer "In4.Cu")
		(net "M_C_CPU0_SB_CS_N<1>")
	)
	(segment
		(start 309.491126 -243.641626)
		(end 309.367936 -243.518436)
		(width 0.18288)
		(layer "In4.Cu")
		(net "M_C_CPU0_SB_CS_N<1>")
	)
	(segment
		(start 336.367882 -243.433346)
		(end 336.357468 -243.42725)
		(width 0.088646)
		(layer "In4.Cu")
		(net "M_C_CPU0_SB_CS_N<1>")
	)
	(segment
		(start 278.418798 -244.794024)
		(end 278.235918 -244.611144)
		(width 0.18288)
		(layer "In4.Cu")
		(net "M_C_CPU0_SB_CS_N<1>")
	)
	(segment
		(start 301.123096 -243.64061)
		(end 300.797214 -243.64061)
		(width 0.18288)
		(layer "In4.Cu")
		(net "M_C_CPU0_SB_CS_N<1>")
	)
	(segment
		(start 316.72276 -244.52199)
		(end 315.631068 -243.430298)
		(width 0.18288)
		(layer "In4.Cu")
		(net "M_C_CPU0_SB_CS_N<1>")
	)
	(segment
		(start 299.852842 -243.43106)
		(end 299.642276 -243.641626)
		(width 0.18288)
		(layer "In4.Cu")
		(net "M_C_CPU0_SB_CS_N<1>")
	)
	(segment
		(start 288.748978 -243.641626)
		(end 285.653226 -243.641626)
		(width 0.18288)
		(layer "In4.Cu")
		(net "M_C_CPU0_SB_CS_N<1>")
	)
	(segment
		(start 278.235918 -243.824506)
		(end 278.053038 -243.641626)
		(width 0.18288)
		(layer "In4.Cu")
		(net "M_C_CPU0_SB_CS_N<1>")
	)
	(segment
		(start 309.367936 -243.518436)
		(end 306.38877 -243.518436)
		(width 0.18288)
		(layer "In4.Cu")
		(net "M_C_CPU0_SB_CS_N<1>")
	)
	(segment
		(start 337.682332 -243.433092)
		(end 337.682078 -243.433346)
		(width 0.088646)
		(layer "In4.Cu")
		(net "M_C_CPU0_SB_CS_N<1>")
	)
	(segment
		(start 289.050222 -243.340382)
		(end 288.748978 -243.641626)
		(width 0.18288)
		(layer "In4.Cu")
		(net "M_C_CPU0_SB_CS_N<1>")
	)
	(segment
		(start 331.176122 -244.52199)
		(end 331.004418 -244.52199)
		(width 0.088646)
		(layer "In4.Cu")
		(net "M_C_CPU0_SB_CS_N<1>")
	)
	(segment
		(start 277.648162 -243.641626)
		(end 276.373082 -244.916706)
		(width 0.18288)
		(layer "In4.Cu")
		(net "M_C_CPU0_SB_CS_N<1>")
	)
	(segment
		(start 284.962346 -243.037614)
		(end 284.779466 -243.220494)
		(width 0.18288)
		(layer "In4.Cu")
		(net "M_C_CPU0_SB_CS_N<1>")
	)
	(segment
		(start 282.311602 -243.824506)
		(end 282.128722 -243.641626)
		(width 0.18288)
		(layer "In4.Cu")
		(net "M_C_CPU0_SB_CS_N<1>")
	)
	(arc
		(start 339.609684 -242.70208)
		(mid 339.374734 -242.63912)
		(end 339.139784 -242.70208)
		(width 0.088646)
		(layer "In4.Cu")
		(net "M_C_CPU0_SB_CS_N<1>")
	)
	(arc
		(start 333.17053 -244.73662)
		(mid 333.122851 -244.91952)
		(end 332.991968 -245.055898)
		(width 0.088646)
		(layer "In4.Cu")
		(net "M_C_CPU0_SB_CS_N<1>")
	)
	(arc
		(start 332.59395 -245.052342)
		(mid 332.317509 -244.985176)
		(end 332.043278 -245.060978)
		(width 0.088646)
		(layer "In4.Cu")
		(net "M_C_CPU0_SB_CS_N<1>")
	)
	(arc
		(start 337.29295 -243.42471)
		(mid 337.016475 -243.35739)
		(end 336.742278 -243.433346)
		(width 0.088646)
		(layer "In4.Cu")
		(net "M_C_CPU0_SB_CS_N<1>")
	)
	(arc
		(start 337.86953 -243.108988)
		(mid 337.819366 -243.296126)
		(end 337.682332 -243.433092)
		(width 0.088646)
		(layer "In4.Cu")
		(net "M_C_CPU0_SB_CS_N<1>")
	)
	(arc
		(start 335.802732 -243.433346)
		(mid 335.615534 -243.483489)
		(end 335.428336 -243.433346)
		(width 0.088646)
		(layer "In4.Cu")
		(net "M_C_CPU0_SB_CS_N<1>")
	)
	(arc
		(start 336.357468 -243.42725)
		(mid 336.07929 -243.357527)
		(end 335.802732 -243.433346)
		(width 0.088646)
		(layer "In4.Cu")
		(net "M_C_CPU0_SB_CS_N<1>")
	)
	(arc
		(start 334.488536 -243.433346)
		(mid 334.214337 -243.357511)
		(end 333.937864 -243.42471)
		(width 0.088646)
		(layer "In4.Cu")
		(net "M_C_CPU0_SB_CS_N<1>")
	)
	(arc
		(start 338.621878 -242.78463)
		(mid 338.43468 -242.734487)
		(end 338.247482 -242.78463)
		(width 0.088646)
		(layer "In4.Cu")
		(net "M_C_CPU0_SB_CS_N<1>")
	)
	(arc
		(start 338.996528 -242.78463)
		(mid 338.80922 -242.834773)
		(end 338.621878 -242.78463)
		(width 0.088646)
		(layer "In4.Cu")
		(net "M_C_CPU0_SB_CS_N<1>")
	)
	(arc
		(start 332.043278 -245.060978)
		(mid 331.953042 -245.098848)
		(end 331.85608 -245.112032)
		(width 0.088646)
		(layer "In4.Cu")
		(net "M_C_CPU0_SB_CS_N<1>")
	)
	(arc
		(start 333.917036 -243.436902)
		(mid 333.714449 -243.643253)
		(end 333.64043 -243.922804)
		(width 0.088646)
		(layer "In4.Cu")
		(net "M_C_CPU0_SB_CS_N<1>")
	)
	(arc
		(start 336.742278 -243.433346)
		(mid 336.55508 -243.483489)
		(end 336.367882 -243.433346)
		(width 0.088646)
		(layer "In4.Cu")
		(net "M_C_CPU0_SB_CS_N<1>")
	)
	(arc
		(start 333.64043 -243.922804)
		(mid 333.592751 -244.105704)
		(end 333.461868 -244.242082)
		(width 0.088646)
		(layer "In4.Cu")
		(net "M_C_CPU0_SB_CS_N<1>")
	)
	(arc
		(start 332.983078 -245.060978)
		(mid 332.79588 -245.111121)
		(end 332.608682 -245.060978)
		(width 0.088646)
		(layer "In4.Cu")
		(net "M_C_CPU0_SB_CS_N<1>")
	)
	(arc
		(start 337.961732 -242.94973)
		(mid 337.894243 -243.016977)
		(end 337.86953 -243.108988)
		(width 0.088646)
		(layer "In4.Cu")
		(net "M_C_CPU0_SB_CS_N<1>")
	)
	(arc
		(start 334.862932 -243.433346)
		(mid 334.675734 -243.483489)
		(end 334.488536 -243.433346)
		(width 0.088646)
		(layer "In4.Cu")
		(net "M_C_CPU0_SB_CS_N<1>")
	)
	(arc
		(start 335.428336 -243.433346)
		(mid 335.154137 -243.357511)
		(end 334.877664 -243.42471)
		(width 0.088646)
		(layer "In4.Cu")
		(net "M_C_CPU0_SB_CS_N<1>")
	)
	(arc
		(start 333.452978 -244.247162)
		(mid 333.248643 -244.449767)
		(end 333.17053 -244.726714)
		(width 0.088646)
		(layer "In4.Cu")
		(net "M_C_CPU0_SB_CS_N<1>")
	)
	(arc
		(start 337.682078 -243.433346)
		(mid 337.495024 -243.483396)
		(end 337.307936 -243.433346)
		(width 0.088646)
		(layer "In4.Cu")
		(net "M_C_CPU0_SB_CS_N<1>")
	)
	(segment
		(start 339.844634 -244.45849)
		(end 339.844634 -243.922804)
		(width 0.20066)
		(layer "F.Cu")
		(net "M_C_CPU0_SB_CS_N<0>")
	)
	(segment
		(start 339.84438 -244.458744)
		(end 339.844634 -244.45849)
		(width 0.20066)
		(layer "F.Cu")
		(net "M_C_CPU0_SB_CS_N<0>")
	)
	(segment
		(start 272.273014 -245.76659)
		(end 271.168114 -245.76659)
		(width 0.20066)
		(layer "F.Cu")
		(net "M_C_CPU0_SB_CS_N<0>")
	)
	(segment
		(start 310.73979 -245.414292)
		(end 307.07838 -245.414292)
		(width 0.18288)
		(layer "In4.Cu")
		(net "M_C_CPU0_SB_CS_N<0>")
	)
	(segment
		(start 314.613798 -245.270274)
		(end 313.546236 -245.270274)
		(width 0.18288)
		(layer "In4.Cu")
		(net "M_C_CPU0_SB_CS_N<0>")
	)
	(segment
		(start 272.697956 -245.341648)
		(end 272.273014 -245.76659)
		(width 0.18288)
		(layer "In4.Cu")
		(net "M_C_CPU0_SB_CS_N<0>")
	)
	(segment
		(start 331.23505 -245.51767)
		(end 331.004418 -245.51767)
		(width 0.088646)
		(layer "In4.Cu")
		(net "M_C_CPU0_SB_CS_N<0>")
	)
	(segment
		(start 277.180294 -246.1133)
		(end 276.997414 -245.93042)
		(width 0.18288)
		(layer "In4.Cu")
		(net "M_C_CPU0_SB_CS_N<0>")
	)
	(segment
		(start 278.196294 -245.341648)
		(end 277.871174 -245.341648)
		(width 0.18288)
		(layer "In4.Cu")
		(net "M_C_CPU0_SB_CS_N<0>")
	)
	(segment
		(start 339.844634 -243.922804)
		(end 339.119972 -243.614702)
		(width 0.088646)
		(layer "In4.Cu")
		(net "M_C_CPU0_SB_CS_N<0>")
	)
	(segment
		(start 299.943266 -245.518686)
		(end 299.766228 -245.341648)
		(width 0.18288)
		(layer "In4.Cu")
		(net "M_C_CPU0_SB_CS_N<0>")
	)
	(segment
		(start 299.766228 -245.341648)
		(end 279.252934 -245.341648)
		(width 0.18288)
		(layer "In4.Cu")
		(net "M_C_CPU0_SB_CS_N<0>")
	)
	(segment
		(start 310.883808 -245.270274)
		(end 310.73979 -245.414292)
		(width 0.18288)
		(layer "In4.Cu")
		(net "M_C_CPU0_SB_CS_N<0>")
	)
	(segment
		(start 276.997414 -245.93042)
		(end 276.997414 -245.524528)
		(width 0.18288)
		(layer "In4.Cu")
		(net "M_C_CPU0_SB_CS_N<0>")
	)
	(segment
		(start 276.814534 -245.341648)
		(end 272.697956 -245.341648)
		(width 0.18288)
		(layer "In4.Cu")
		(net "M_C_CPU0_SB_CS_N<0>")
	)
	(segment
		(start 313.25185 -245.56466)
		(end 312.852562 -245.56466)
		(width 0.18288)
		(layer "In4.Cu")
		(net "M_C_CPU0_SB_CS_N<0>")
	)
	(segment
		(start 278.379174 -245.93042)
		(end 278.379174 -245.524528)
		(width 0.18288)
		(layer "In4.Cu")
		(net "M_C_CPU0_SB_CS_N<0>")
	)
	(segment
		(start 278.562054 -246.1133)
		(end 278.379174 -245.93042)
		(width 0.18288)
		(layer "In4.Cu")
		(net "M_C_CPU0_SB_CS_N<0>")
	)
	(segment
		(start 278.379174 -245.524528)
		(end 278.196294 -245.341648)
		(width 0.18288)
		(layer "In4.Cu")
		(net "M_C_CPU0_SB_CS_N<0>")
	)
	(segment
		(start 334.11033 -244.726714)
		(end 334.11033 -244.73662)
		(width 0.088646)
		(layer "In4.Cu")
		(net "M_C_CPU0_SB_CS_N<0>")
	)
	(segment
		(start 331.856334 -245.799356)
		(end 331.516736 -245.799356)
		(width 0.088646)
		(layer "In4.Cu")
		(net "M_C_CPU0_SB_CS_N<0>")
	)
	(segment
		(start 276.997414 -245.524528)
		(end 276.814534 -245.341648)
		(width 0.18288)
		(layer "In4.Cu")
		(net "M_C_CPU0_SB_CS_N<0>")
	)
	(segment
		(start 337.227164 -244.238526)
		(end 337.212432 -244.247162)
		(width 0.088646)
		(layer "In4.Cu")
		(net "M_C_CPU0_SB_CS_N<0>")
	)
	(segment
		(start 277.688294 -245.93042)
		(end 277.505414 -246.1133)
		(width 0.18288)
		(layer "In4.Cu")
		(net "M_C_CPU0_SB_CS_N<0>")
	)
	(segment
		(start 306.825904 -245.161816)
		(end 306.399438 -245.161816)
		(width 0.18288)
		(layer "In4.Cu")
		(net "M_C_CPU0_SB_CS_N<0>")
	)
	(segment
		(start 279.070054 -245.93042)
		(end 278.887174 -246.1133)
		(width 0.18288)
		(layer "In4.Cu")
		(net "M_C_CPU0_SB_CS_N<0>")
	)
	(segment
		(start 303.263046 -245.518686)
		(end 299.943266 -245.518686)
		(width 0.18288)
		(layer "In4.Cu")
		(net "M_C_CPU0_SB_CS_N<0>")
	)
	(segment
		(start 333.931768 -245.055898)
		(end 333.922878 -245.060978)
		(width 0.088646)
		(layer "In4.Cu")
		(net "M_C_CPU0_SB_CS_N<0>")
	)
	(segment
		(start 339.119972 -243.614702)
		(end 339.092032 -243.598446)
		(width 0.088646)
		(layer "In4.Cu")
		(net "M_C_CPU0_SB_CS_N<0>")
	)
	(segment
		(start 314.861194 -245.51767)
		(end 314.613798 -245.270274)
		(width 0.18288)
		(layer "In4.Cu")
		(net "M_C_CPU0_SB_CS_N<0>")
	)
	(segment
		(start 336.287364 -244.238526)
		(end 336.272632 -244.247162)
		(width 0.088646)
		(layer "In4.Cu")
		(net "M_C_CPU0_SB_CS_N<0>")
	)
	(segment
		(start 303.464976 -245.316756)
		(end 303.263046 -245.518686)
		(width 0.18288)
		(layer "In4.Cu")
		(net "M_C_CPU0_SB_CS_N<0>")
	)
	(segment
		(start 306.244498 -245.316756)
		(end 303.464976 -245.316756)
		(width 0.18288)
		(layer "In4.Cu")
		(net "M_C_CPU0_SB_CS_N<0>")
	)
	(segment
		(start 338.152232 -244.247162)
		(end 338.151978 -244.247162)
		(width 0.088646)
		(layer "In4.Cu")
		(net "M_C_CPU0_SB_CS_N<0>")
	)
	(segment
		(start 313.546236 -245.270274)
		(end 313.25185 -245.56466)
		(width 0.18288)
		(layer "In4.Cu")
		(net "M_C_CPU0_SB_CS_N<0>")
	)
	(segment
		(start 307.07838 -245.414292)
		(end 306.825904 -245.161816)
		(width 0.18288)
		(layer "In4.Cu")
		(net "M_C_CPU0_SB_CS_N<0>")
	)
	(segment
		(start 277.871174 -245.341648)
		(end 277.688294 -245.524528)
		(width 0.18288)
		(layer "In4.Cu")
		(net "M_C_CPU0_SB_CS_N<0>")
	)
	(segment
		(start 312.852562 -245.56466)
		(end 312.558176 -245.270274)
		(width 0.18288)
		(layer "In4.Cu")
		(net "M_C_CPU0_SB_CS_N<0>")
	)
	(segment
		(start 339.092032 -243.598446)
		(end 339.091778 -243.598446)
		(width 0.088646)
		(layer "In4.Cu")
		(net "M_C_CPU0_SB_CS_N<0>")
	)
	(segment
		(start 277.688294 -245.524528)
		(end 277.688294 -245.93042)
		(width 0.18288)
		(layer "In4.Cu")
		(net "M_C_CPU0_SB_CS_N<0>")
	)
	(segment
		(start 335.342992 -244.241066)
		(end 335.332578 -244.247162)
		(width 0.088646)
		(layer "In4.Cu")
		(net "M_C_CPU0_SB_CS_N<0>")
	)
	(segment
		(start 333.462122 -245.869968)
		(end 333.453232 -245.875048)
		(width 0.088646)
		(layer "In4.Cu")
		(net "M_C_CPU0_SB_CS_N<0>")
	)
	(segment
		(start 279.252934 -245.341648)
		(end 279.070054 -245.524528)
		(width 0.18288)
		(layer "In4.Cu")
		(net "M_C_CPU0_SB_CS_N<0>")
	)
	(segment
		(start 306.399438 -245.161816)
		(end 306.244498 -245.316756)
		(width 0.18288)
		(layer "In4.Cu")
		(net "M_C_CPU0_SB_CS_N<0>")
	)
	(segment
		(start 312.558176 -245.270274)
		(end 310.883808 -245.270274)
		(width 0.18288)
		(layer "In4.Cu")
		(net "M_C_CPU0_SB_CS_N<0>")
	)
	(segment
		(start 279.070054 -245.524528)
		(end 279.070054 -245.93042)
		(width 0.18288)
		(layer "In4.Cu")
		(net "M_C_CPU0_SB_CS_N<0>")
	)
	(segment
		(start 333.640684 -245.528592)
		(end 333.640684 -245.55069)
		(width 0.088646)
		(layer "In4.Cu")
		(net "M_C_CPU0_SB_CS_N<0>")
	)
	(segment
		(start 338.152486 -244.246908)
		(end 338.152232 -244.247162)
		(width 0.088646)
		(layer "In4.Cu")
		(net "M_C_CPU0_SB_CS_N<0>")
	)
	(segment
		(start 331.004418 -245.51767)
		(end 314.861194 -245.51767)
		(width 0.18288)
		(layer "In4.Cu")
		(net "M_C_CPU0_SB_CS_N<0>")
	)
	(segment
		(start 331.516736 -245.799356)
		(end 331.23505 -245.51767)
		(width 0.088646)
		(layer "In4.Cu")
		(net "M_C_CPU0_SB_CS_N<0>")
	)
	(segment
		(start 277.505414 -246.1133)
		(end 277.180294 -246.1133)
		(width 0.18288)
		(layer "In4.Cu")
		(net "M_C_CPU0_SB_CS_N<0>")
	)
	(segment
		(start 338.717636 -243.598446)
		(end 338.431632 -243.7638)
		(width 0.088646)
		(layer "In4.Cu")
		(net "M_C_CPU0_SB_CS_N<0>")
	)
	(segment
		(start 278.887174 -246.1133)
		(end 278.562054 -246.1133)
		(width 0.18288)
		(layer "In4.Cu")
		(net "M_C_CPU0_SB_CS_N<0>")
	)
	(arc
		(start 335.332578 -244.247162)
		(mid 335.14538 -244.297305)
		(end 334.958182 -244.247162)
		(width 0.088646)
		(layer "In4.Cu")
		(net "M_C_CPU0_SB_CS_N<0>")
	)
	(arc
		(start 333.922878 -245.060978)
		(mid 333.721596 -245.258465)
		(end 333.640684 -245.528592)
		(width 0.088646)
		(layer "In4.Cu")
		(net "M_C_CPU0_SB_CS_N<0>")
	)
	(arc
		(start 334.392778 -244.247162)
		(mid 334.188443 -244.449767)
		(end 334.11033 -244.726714)
		(width 0.088646)
		(layer "In4.Cu")
		(net "M_C_CPU0_SB_CS_N<0>")
	)
	(arc
		(start 337.777836 -244.247162)
		(mid 337.503637 -244.171327)
		(end 337.227164 -244.238526)
		(width 0.088646)
		(layer "In4.Cu")
		(net "M_C_CPU0_SB_CS_N<0>")
	)
	(arc
		(start 337.212432 -244.247162)
		(mid 337.025234 -244.297305)
		(end 336.838036 -244.247162)
		(width 0.088646)
		(layer "In4.Cu")
		(net "M_C_CPU0_SB_CS_N<0>")
	)
	(arc
		(start 332.513432 -245.875048)
		(mid 332.326234 -245.925191)
		(end 332.139036 -245.875048)
		(width 0.088646)
		(layer "In4.Cu")
		(net "M_C_CPU0_SB_CS_N<0>")
	)
	(arc
		(start 338.431632 -243.7638)
		(mid 338.364302 -243.830958)
		(end 338.339684 -243.922804)
		(width 0.088646)
		(layer "In4.Cu")
		(net "M_C_CPU0_SB_CS_N<0>")
	)
	(arc
		(start 334.958182 -244.247162)
		(mid 334.67548 -244.171386)
		(end 334.392778 -244.247162)
		(width 0.088646)
		(layer "In4.Cu")
		(net "M_C_CPU0_SB_CS_N<0>")
	)
	(arc
		(start 338.151978 -244.247162)
		(mid 337.964924 -244.297246)
		(end 337.777836 -244.247162)
		(width 0.088646)
		(layer "In4.Cu")
		(net "M_C_CPU0_SB_CS_N<0>")
	)
	(arc
		(start 335.898236 -244.247162)
		(mid 335.621423 -244.171292)
		(end 335.342992 -244.241066)
		(width 0.088646)
		(layer "In4.Cu")
		(net "M_C_CPU0_SB_CS_N<0>")
	)
	(arc
		(start 336.272632 -244.247162)
		(mid 336.085434 -244.297305)
		(end 335.898236 -244.247162)
		(width 0.088646)
		(layer "In4.Cu")
		(net "M_C_CPU0_SB_CS_N<0>")
	)
	(arc
		(start 336.838036 -244.247162)
		(mid 336.563837 -244.171327)
		(end 336.287364 -244.238526)
		(width 0.088646)
		(layer "In4.Cu")
		(net "M_C_CPU0_SB_CS_N<0>")
	)
	(arc
		(start 338.339684 -243.922804)
		(mid 338.28952 -244.109942)
		(end 338.152486 -244.246908)
		(width 0.088646)
		(layer "In4.Cu")
		(net "M_C_CPU0_SB_CS_N<0>")
	)
	(arc
		(start 332.139036 -245.875048)
		(mid 332.00267 -245.81857)
		(end 331.856334 -245.799356)
		(width 0.088646)
		(layer "In4.Cu")
		(net "M_C_CPU0_SB_CS_N<0>")
	)
	(arc
		(start 339.091778 -243.598446)
		(mid 338.904724 -243.548362)
		(end 338.717636 -243.598446)
		(width 0.088646)
		(layer "In4.Cu")
		(net "M_C_CPU0_SB_CS_N<0>")
	)
	(arc
		(start 334.11033 -244.73662)
		(mid 334.062651 -244.91952)
		(end 333.931768 -245.055898)
		(width 0.088646)
		(layer "In4.Cu")
		(net "M_C_CPU0_SB_CS_N<0>")
	)
	(arc
		(start 333.640684 -245.55069)
		(mid 333.593005 -245.73359)
		(end 333.462122 -245.869968)
		(width 0.088646)
		(layer "In4.Cu")
		(net "M_C_CPU0_SB_CS_N<0>")
	)
	(arc
		(start 333.078836 -245.875048)
		(mid 332.796134 -245.799272)
		(end 332.513432 -245.875048)
		(width 0.088646)
		(layer "In4.Cu")
		(net "M_C_CPU0_SB_CS_N<0>")
	)
	(arc
		(start 333.453232 -245.875048)
		(mid 333.266034 -245.925191)
		(end 333.078836 -245.875048)
		(width 0.088646)
		(layer "In4.Cu")
		(net "M_C_CPU0_SB_CS_N<0>")
	)
	(segment
		(start 277.091394 -239.249204)
		(end 277.091394 -239.09274)
		(width 0.20066)
		(layer "F.Cu")
		(net "M_C_CPU0_SB_CB<7>")
	)
	(segment
		(start 281.121866 -238.86287)
		(end 280.806906 -238.86287)
		(width 0.20066)
		(layer "F.Cu")
		(net "M_C_CPU0_SB_CB<7>")
	)
	(segment
		(start 276.96541 -238.966756)
		(end 275.268182 -238.966756)
		(width 0.20066)
		(layer "F.Cu")
		(net "M_C_CPU0_SB_CB<7>")
	)
	(segment
		(start 282.811982 -238.966756)
		(end 281.90952 -238.966756)
		(width 0.20066)
		(layer "F.Cu")
		(net "M_C_CPU0_SB_CB<7>")
	)
	(segment
		(start 283.916882 -238.966756)
		(end 282.811982 -238.966756)
		(width 0.20066)
		(layer "F.Cu")
		(net "M_C_CPU0_SB_CB<7>")
	)
	(segment
		(start 280.457148 -239.391698)
		(end 279.98166 -239.391698)
		(width 0.20066)
		(layer "F.Cu")
		(net "M_C_CPU0_SB_CB<7>")
	)
	(segment
		(start 280.606246 -239.2426)
		(end 280.457148 -239.391698)
		(width 0.20066)
		(layer "F.Cu")
		(net "M_C_CPU0_SB_CB<7>")
	)
	(segment
		(start 281.798522 -239.077754)
		(end 281.33675 -239.077754)
		(width 0.20066)
		(layer "F.Cu")
		(net "M_C_CPU0_SB_CB<7>")
	)
	(segment
		(start 277.091394 -239.09274)
		(end 276.96541 -238.966756)
		(width 0.20066)
		(layer "F.Cu")
		(net "M_C_CPU0_SB_CB<7>")
	)
	(segment
		(start 279.98166 -239.391698)
		(end 279.912826 -239.391698)
		(width 0.101854)
		(layer "F.Cu")
		(net "M_C_CPU0_SB_CB<7>")
	)
	(segment
		(start 341.724234 -241.202972)
		(end 341.724234 -240.667286)
		(width 0.20066)
		(layer "F.Cu")
		(net "M_C_CPU0_SB_CB<7>")
	)
	(segment
		(start 341.72398 -241.203226)
		(end 341.724234 -241.202972)
		(width 0.20066)
		(layer "F.Cu")
		(net "M_C_CPU0_SB_CB<7>")
	)
	(segment
		(start 277.45309 -239.391698)
		(end 277.233888 -239.391698)
		(width 0.20066)
		(layer "F.Cu")
		(net "M_C_CPU0_SB_CB<7>")
	)
	(segment
		(start 280.606246 -239.06353)
		(end 280.606246 -239.2426)
		(width 0.20066)
		(layer "F.Cu")
		(net "M_C_CPU0_SB_CB<7>")
	)
	(segment
		(start 277.839932 -239.391698)
		(end 277.45309 -239.391698)
		(width 0.101854)
		(layer "F.Cu")
		(net "M_C_CPU0_SB_CB<7>")
	)
	(segment
		(start 280.806906 -238.86287)
		(end 280.606246 -239.06353)
		(width 0.20066)
		(layer "F.Cu")
		(net "M_C_CPU0_SB_CB<7>")
	)
	(segment
		(start 281.33675 -239.077754)
		(end 281.121866 -238.86287)
		(width 0.20066)
		(layer "F.Cu")
		(net "M_C_CPU0_SB_CB<7>")
	)
	(segment
		(start 277.233888 -239.391698)
		(end 277.091394 -239.249204)
		(width 0.20066)
		(layer "F.Cu")
		(net "M_C_CPU0_SB_CB<7>")
	)
	(segment
		(start 281.90952 -238.966756)
		(end 281.798522 -239.077754)
		(width 0.20066)
		(layer "F.Cu")
		(net "M_C_CPU0_SB_CB<7>")
	)
	(segment
		(start 279.912826 -239.391698)
		(end 277.839932 -239.391698)
		(width 0.1016)
		(layer "F.Cu")
		(net "M_C_CPU0_SB_CB<7>")
	)
	(segment
		(start 285.914084 -239.394746)
		(end 285.731204 -239.577626)
		(width 0.18288)
		(layer "In4.Cu")
		(net "M_C_CPU0_SB_CB<7>")
	)
	(segment
		(start 341.724234 -240.667286)
		(end 341.72398 -240.66754)
		(width 0.088646)
		(layer "In4.Cu")
		(net "M_C_CPU0_SB_CB<7>")
	)
	(segment
		(start 331.267054 -242.08359)
		(end 331.004164 -242.08359)
		(width 0.088646)
		(layer "In4.Cu")
		(net "M_C_CPU0_SB_CB<7>")
	)
	(segment
		(start 297.157394 -240.240312)
		(end 294.259254 -240.240312)
		(width 0.18288)
		(layer "In4.Cu")
		(net "M_C_CPU0_SB_CB<7>")
	)
	(segment
		(start 340.596982 -240.342928)
		(end 340.59114 -240.34623)
		(width 0.088646)
		(layer "In4.Cu")
		(net "M_C_CPU0_SB_CB<7>")
	)
	(segment
		(start 286.604964 -238.953294)
		(end 286.422084 -238.770414)
		(width 0.18288)
		(layer "In4.Cu")
		(net "M_C_CPU0_SB_CB<7>")
	)
	(segment
		(start 302.9966 -239.391698)
		(end 298.006008 -239.391698)
		(width 0.18288)
		(layer "In4.Cu")
		(net "M_C_CPU0_SB_CB<7>")
	)
	(segment
		(start 285.914084 -238.953294)
		(end 285.914084 -239.394746)
		(width 0.18288)
		(layer "In4.Cu")
		(net "M_C_CPU0_SB_CB<7>")
	)
	(segment
		(start 289.672522 -238.618776)
		(end 288.692336 -238.618776)
		(width 0.18288)
		(layer "In4.Cu")
		(net "M_C_CPU0_SB_CB<7>")
	)
	(segment
		(start 332.522068 -242.614196)
		(end 332.513178 -242.619276)
		(width 0.088646)
		(layer "In4.Cu")
		(net "M_C_CPU0_SB_CB<7>")
	)
	(segment
		(start 288.692336 -238.618776)
		(end 287.733486 -239.577626)
		(width 0.18288)
		(layer "In4.Cu")
		(net "M_C_CPU0_SB_CB<7>")
	)
	(segment
		(start 336.843624 -240.994946)
		(end 336.837782 -240.991644)
		(width 0.088646)
		(layer "In4.Cu")
		(net "M_C_CPU0_SB_CB<7>")
	)
	(segment
		(start 339.663024 -240.339372)
		(end 339.657182 -240.342928)
		(width 0.088646)
		(layer "In4.Cu")
		(net "M_C_CPU0_SB_CB<7>")
	)
	(segment
		(start 337.783424 -240.994946)
		(end 337.77174 -240.988342)
		(width 0.088646)
		(layer "In4.Cu")
		(net "M_C_CPU0_SB_CB<7>")
	)
	(segment
		(start 306.941982 -238.714026)
		(end 303.674272 -238.714026)
		(width 0.18288)
		(layer "In4.Cu")
		(net "M_C_CPU0_SB_CB<7>")
	)
	(segment
		(start 332.998064 -241.796824)
		(end 332.983332 -241.80546)
		(width 0.088646)
		(layer "In4.Cu")
		(net "M_C_CPU0_SB_CB<7>")
	)
	(segment
		(start 290.546282 -239.635792)
		(end 290.363402 -239.818672)
		(width 0.18288)
		(layer "In4.Cu")
		(net "M_C_CPU0_SB_CB<7>")
	)
	(segment
		(start 307.177948 -238.47806)
		(end 306.941982 -238.714026)
		(width 0.18288)
		(layer "In4.Cu")
		(net "M_C_CPU0_SB_CB<7>")
	)
	(segment
		(start 308.733952 -238.47806)
		(end 307.177948 -238.47806)
		(width 0.18288)
		(layer "In4.Cu")
		(net "M_C_CPU0_SB_CB<7>")
	)
	(segment
		(start 332.983332 -241.80546)
		(end 332.977236 -241.809016)
		(width 0.088646)
		(layer "In4.Cu")
		(net "M_C_CPU0_SB_CB<7>")
	)
	(segment
		(start 310.826912 -239.573816)
		(end 309.829708 -239.573816)
		(width 0.18288)
		(layer "In4.Cu")
		(net "M_C_CPU0_SB_CB<7>")
	)
	(segment
		(start 290.729162 -238.618776)
		(end 290.546282 -238.801656)
		(width 0.18288)
		(layer "In4.Cu")
		(net "M_C_CPU0_SB_CB<7>")
	)
	(segment
		(start 287.733486 -239.577626)
		(end 286.787844 -239.577626)
		(width 0.18288)
		(layer "In4.Cu")
		(net "M_C_CPU0_SB_CB<7>")
	)
	(segment
		(start 311.0103 -239.390428)
		(end 310.826912 -239.573816)
		(width 0.18288)
		(layer "In4.Cu")
		(net "M_C_CPU0_SB_CB<7>")
	)
	(segment
		(start 290.038282 -239.818672)
		(end 289.855402 -239.635792)
		(width 0.18288)
		(layer "In4.Cu")
		(net "M_C_CPU0_SB_CB<7>")
	)
	(segment
		(start 309.829708 -239.573816)
		(end 308.733952 -238.47806)
		(width 0.18288)
		(layer "In4.Cu")
		(net "M_C_CPU0_SB_CB<7>")
	)
	(segment
		(start 338.723224 -240.994946)
		(end 338.71154 -240.988342)
		(width 0.088646)
		(layer "In4.Cu")
		(net "M_C_CPU0_SB_CB<7>")
	)
	(segment
		(start 292.15588 -239.197642)
		(end 292.15588 -238.803942)
		(width 0.18288)
		(layer "In4.Cu")
		(net "M_C_CPU0_SB_CB<7>")
	)
	(segment
		(start 294.259254 -240.240312)
		(end 293.413434 -239.394492)
		(width 0.18288)
		(layer "In4.Cu")
		(net "M_C_CPU0_SB_CB<7>")
	)
	(segment
		(start 341.367872 -240.571782)
		(end 340.971632 -240.342674)
		(width 0.088646)
		(layer "In4.Cu")
		(net "M_C_CPU0_SB_CB<7>")
	)
	(segment
		(start 331.004164 -242.08359)
		(end 318.107822 -242.08359)
		(width 0.18288)
		(layer "In4.Cu")
		(net "M_C_CPU0_SB_CB<7>")
	)
	(segment
		(start 284.527752 -239.577626)
		(end 283.916882 -238.966756)
		(width 0.18288)
		(layer "In4.Cu")
		(net "M_C_CPU0_SB_CB<7>")
	)
	(segment
		(start 292.35273 -239.394492)
		(end 292.15588 -239.197642)
		(width 0.18288)
		(layer "In4.Cu")
		(net "M_C_CPU0_SB_CB<7>")
	)
	(segment
		(start 303.674272 -238.714026)
		(end 302.9966 -239.391698)
		(width 0.18288)
		(layer "In4.Cu")
		(net "M_C_CPU0_SB_CB<7>")
	)
	(segment
		(start 292.15588 -238.803942)
		(end 291.970714 -238.618776)
		(width 0.18288)
		(layer "In4.Cu")
		(net "M_C_CPU0_SB_CB<7>")
	)
	(segment
		(start 339.484208 -240.512346)
		(end 339.362288 -240.726722)
		(width 0.088646)
		(layer "In4.Cu")
		(net "M_C_CPU0_SB_CB<7>")
	)
	(segment
		(start 298.006008 -239.391698)
		(end 297.157394 -240.240312)
		(width 0.18288)
		(layer "In4.Cu")
		(net "M_C_CPU0_SB_CB<7>")
	)
	(segment
		(start 291.970714 -238.618776)
		(end 290.729162 -238.618776)
		(width 0.18288)
		(layer "In4.Cu")
		(net "M_C_CPU0_SB_CB<7>")
	)
	(segment
		(start 331.856334 -242.543584)
		(end 331.727048 -242.543584)
		(width 0.088646)
		(layer "In4.Cu")
		(net "M_C_CPU0_SB_CB<7>")
	)
	(segment
		(start 339.657182 -240.342928)
		(end 339.65134 -240.34623)
		(width 0.088646)
		(layer "In4.Cu")
		(net "M_C_CPU0_SB_CB<7>")
	)
	(segment
		(start 289.855402 -239.635792)
		(end 289.855402 -238.801656)
		(width 0.18288)
		(layer "In4.Cu")
		(net "M_C_CPU0_SB_CB<7>")
	)
	(segment
		(start 286.096964 -238.770414)
		(end 285.914084 -238.953294)
		(width 0.18288)
		(layer "In4.Cu")
		(net "M_C_CPU0_SB_CB<7>")
	)
	(segment
		(start 290.546282 -238.801656)
		(end 290.546282 -239.635792)
		(width 0.18288)
		(layer "In4.Cu")
		(net "M_C_CPU0_SB_CB<7>")
	)
	(segment
		(start 336.837782 -240.991644)
		(end 336.83321 -240.989104)
		(width 0.088646)
		(layer "In4.Cu")
		(net "M_C_CPU0_SB_CB<7>")
	)
	(segment
		(start 286.787844 -239.577626)
		(end 286.604964 -239.394746)
		(width 0.18288)
		(layer "In4.Cu")
		(net "M_C_CPU0_SB_CB<7>")
	)
	(segment
		(start 315.41466 -239.390428)
		(end 311.0103 -239.390428)
		(width 0.18288)
		(layer "In4.Cu")
		(net "M_C_CPU0_SB_CB<7>")
	)
	(segment
		(start 293.413434 -239.394492)
		(end 292.35273 -239.394492)
		(width 0.18288)
		(layer "In4.Cu")
		(net "M_C_CPU0_SB_CB<7>")
	)
	(segment
		(start 334.871822 -241.80038)
		(end 334.862932 -241.80546)
		(width 0.088646)
		(layer "In4.Cu")
		(net "M_C_CPU0_SB_CB<7>")
	)
	(segment
		(start 318.107822 -242.08359)
		(end 315.41466 -239.390428)
		(width 0.18288)
		(layer "In4.Cu")
		(net "M_C_CPU0_SB_CB<7>")
	)
	(segment
		(start 286.422084 -238.770414)
		(end 286.096964 -238.770414)
		(width 0.18288)
		(layer "In4.Cu")
		(net "M_C_CPU0_SB_CB<7>")
	)
	(segment
		(start 335.050384 -241.471196)
		(end 335.050384 -241.481102)
		(width 0.088646)
		(layer "In4.Cu")
		(net "M_C_CPU0_SB_CB<7>")
	)
	(segment
		(start 289.855402 -238.801656)
		(end 289.672522 -238.618776)
		(width 0.18288)
		(layer "In4.Cu")
		(net "M_C_CPU0_SB_CB<7>")
	)
	(segment
		(start 340.602824 -240.339372)
		(end 340.596982 -240.342928)
		(width 0.088646)
		(layer "In4.Cu")
		(net "M_C_CPU0_SB_CB<7>")
	)
	(segment
		(start 331.727048 -242.543584)
		(end 331.267054 -242.08359)
		(width 0.088646)
		(layer "In4.Cu")
		(net "M_C_CPU0_SB_CB<7>")
	)
	(segment
		(start 290.363402 -239.818672)
		(end 290.038282 -239.818672)
		(width 0.18288)
		(layer "In4.Cu")
		(net "M_C_CPU0_SB_CB<7>")
	)
	(segment
		(start 286.604964 -239.394746)
		(end 286.604964 -238.953294)
		(width 0.18288)
		(layer "In4.Cu")
		(net "M_C_CPU0_SB_CB<7>")
	)
	(segment
		(start 285.731204 -239.577626)
		(end 284.527752 -239.577626)
		(width 0.18288)
		(layer "In4.Cu")
		(net "M_C_CPU0_SB_CB<7>")
	)
	(arc
		(start 335.332832 -240.991644)
		(mid 335.128497 -241.194249)
		(end 335.050384 -241.471196)
		(width 0.088646)
		(layer "In4.Cu")
		(net "M_C_CPU0_SB_CB<7>")
	)
	(arc
		(start 333.548736 -241.80546)
		(mid 333.274537 -241.729625)
		(end 332.998064 -241.796824)
		(width 0.088646)
		(layer "In4.Cu")
		(net "M_C_CPU0_SB_CB<7>")
	)
	(arc
		(start 335.050384 -241.481102)
		(mid 335.002705 -241.664002)
		(end 334.871822 -241.80038)
		(width 0.088646)
		(layer "In4.Cu")
		(net "M_C_CPU0_SB_CB<7>")
	)
	(arc
		(start 336.83321 -240.989104)
		(mid 336.552575 -240.915936)
		(end 336.272632 -240.991644)
		(width 0.088646)
		(layer "In4.Cu")
		(net "M_C_CPU0_SB_CB<7>")
	)
	(arc
		(start 332.138782 -242.619276)
		(mid 332.002539 -242.56283)
		(end 331.856334 -242.543584)
		(width 0.088646)
		(layer "In4.Cu")
		(net "M_C_CPU0_SB_CB<7>")
	)
	(arc
		(start 340.971632 -240.342674)
		(mid 340.787678 -240.292579)
		(end 340.602824 -240.339372)
		(width 0.088646)
		(layer "In4.Cu")
		(net "M_C_CPU0_SB_CB<7>")
	)
	(arc
		(start 333.923132 -241.80546)
		(mid 333.735934 -241.855603)
		(end 333.548736 -241.80546)
		(width 0.088646)
		(layer "In4.Cu")
		(net "M_C_CPU0_SB_CB<7>")
	)
	(arc
		(start 339.65134 -240.34623)
		(mid 339.599995 -240.380495)
		(end 339.55355 -240.42116)
		(width 0.088646)
		(layer "In4.Cu")
		(net "M_C_CPU0_SB_CB<7>")
	)
	(arc
		(start 332.70063 -242.294918)
		(mid 332.652951 -242.477818)
		(end 332.522068 -242.614196)
		(width 0.088646)
		(layer "In4.Cu")
		(net "M_C_CPU0_SB_CB<7>")
	)
	(arc
		(start 337.77174 -240.988342)
		(mid 337.491635 -240.9159)
		(end 337.212432 -240.991644)
		(width 0.088646)
		(layer "In4.Cu")
		(net "M_C_CPU0_SB_CB<7>")
	)
	(arc
		(start 338.152232 -240.991644)
		(mid 337.968278 -241.041773)
		(end 337.783424 -240.994946)
		(width 0.088646)
		(layer "In4.Cu")
		(net "M_C_CPU0_SB_CB<7>")
	)
	(arc
		(start 341.72398 -240.66754)
		(mid 341.539627 -240.643104)
		(end 341.367872 -240.571782)
		(width 0.088646)
		(layer "In4.Cu")
		(net "M_C_CPU0_SB_CB<7>")
	)
	(arc
		(start 334.488536 -241.80546)
		(mid 334.205834 -241.729684)
		(end 333.923132 -241.80546)
		(width 0.088646)
		(layer "In4.Cu")
		(net "M_C_CPU0_SB_CB<7>")
	)
	(arc
		(start 340.031832 -240.342674)
		(mid 339.847878 -240.292579)
		(end 339.663024 -240.339372)
		(width 0.088646)
		(layer "In4.Cu")
		(net "M_C_CPU0_SB_CB<7>")
	)
	(arc
		(start 337.212432 -240.991644)
		(mid 337.028478 -241.041773)
		(end 336.843624 -240.994946)
		(width 0.088646)
		(layer "In4.Cu")
		(net "M_C_CPU0_SB_CB<7>")
	)
	(arc
		(start 335.898236 -240.991644)
		(mid 335.615534 -240.915868)
		(end 335.332832 -240.991644)
		(width 0.088646)
		(layer "In4.Cu")
		(net "M_C_CPU0_SB_CB<7>")
	)
	(arc
		(start 332.977236 -241.809016)
		(mid 332.774649 -242.015367)
		(end 332.70063 -242.294918)
		(width 0.088646)
		(layer "In4.Cu")
		(net "M_C_CPU0_SB_CB<7>")
	)
	(arc
		(start 336.272632 -240.991644)
		(mid 336.085434 -241.041787)
		(end 335.898236 -240.991644)
		(width 0.088646)
		(layer "In4.Cu")
		(net "M_C_CPU0_SB_CB<7>")
	)
	(arc
		(start 334.862932 -241.80546)
		(mid 334.675734 -241.855603)
		(end 334.488536 -241.80546)
		(width 0.088646)
		(layer "In4.Cu")
		(net "M_C_CPU0_SB_CB<7>")
	)
	(arc
		(start 332.513178 -242.619276)
		(mid 332.32598 -242.669419)
		(end 332.138782 -242.619276)
		(width 0.088646)
		(layer "In4.Cu")
		(net "M_C_CPU0_SB_CB<7>")
	)
	(arc
		(start 340.59114 -240.34623)
		(mid 340.311005 -240.418546)
		(end 340.031832 -240.342674)
		(width 0.088646)
		(layer "In4.Cu")
		(net "M_C_CPU0_SB_CB<7>")
	)
	(arc
		(start 338.71154 -240.988342)
		(mid 338.431435 -240.9159)
		(end 338.152232 -240.991644)
		(width 0.088646)
		(layer "In4.Cu")
		(net "M_C_CPU0_SB_CB<7>")
	)
	(arc
		(start 339.256878 -240.865152)
		(mid 339.178588 -240.933782)
		(end 339.092032 -240.991644)
		(width 0.088646)
		(layer "In4.Cu")
		(net "M_C_CPU0_SB_CB<7>")
	)
	(arc
		(start 339.092032 -240.991644)
		(mid 338.908078 -241.041773)
		(end 338.723224 -240.994946)
		(width 0.088646)
		(layer "In4.Cu")
		(net "M_C_CPU0_SB_CB<7>")
	)
	(arc
		(start 339.362288 -240.726722)
		(mid 339.314246 -240.799488)
		(end 339.256878 -240.865152)
		(width 0.088646)
		(layer "In4.Cu")
		(net "M_C_CPU0_SB_CB<7>")
	)
	(arc
		(start 339.55355 -240.42116)
		(mid 339.51581 -240.464419)
		(end 339.484208 -240.512346)
		(width 0.088646)
		(layer "In4.Cu")
		(net "M_C_CPU0_SB_CB<7>")
	)
	(segment
		(start 341.254334 -242.017042)
		(end 341.25408 -242.016788)
		(width 0.20066)
		(layer "F.Cu")
		(net "M_C_CPU0_SB_CB<6>")
	)
	(segment
		(start 280.525474 -240.241836)
		(end 279.981406 -240.241836)
		(width 0.20066)
		(layer "F.Cu")
		(net "M_C_CPU0_SB_CB<6>")
	)
	(segment
		(start 277.452836 -240.241836)
		(end 276.840188 -240.241836)
		(width 0.20066)
		(layer "F.Cu")
		(net "M_C_CPU0_SB_CB<6>")
	)
	(segment
		(start 283.916882 -240.666778)
		(end 282.811982 -240.666778)
		(width 0.20066)
		(layer "F.Cu")
		(net "M_C_CPU0_SB_CB<6>")
	)
	(segment
		(start 280.924762 -240.946432)
		(end 280.689558 -240.711228)
		(width 0.20066)
		(layer "F.Cu")
		(net "M_C_CPU0_SB_CB<6>")
	)
	(segment
		(start 281.497278 -240.666778)
		(end 281.217624 -240.946432)
		(width 0.20066)
		(layer "F.Cu")
		(net "M_C_CPU0_SB_CB<6>")
	)
	(segment
		(start 276.840188 -240.241836)
		(end 276.415246 -240.666778)
		(width 0.20066)
		(layer "F.Cu")
		(net "M_C_CPU0_SB_CB<6>")
	)
	(segment
		(start 279.912826 -240.241836)
		(end 277.852886 -240.241836)
		(width 0.1016)
		(layer "F.Cu")
		(net "M_C_CPU0_SB_CB<6>")
	)
	(segment
		(start 341.25408 -242.016788)
		(end 341.25408 -241.481102)
		(width 0.20066)
		(layer "F.Cu")
		(net "M_C_CPU0_SB_CB<6>")
	)
	(segment
		(start 276.415246 -240.666778)
		(end 275.268182 -240.666778)
		(width 0.20066)
		(layer "F.Cu")
		(net "M_C_CPU0_SB_CB<6>")
	)
	(segment
		(start 280.689558 -240.40592)
		(end 280.525474 -240.241836)
		(width 0.20066)
		(layer "F.Cu")
		(net "M_C_CPU0_SB_CB<6>")
	)
	(segment
		(start 277.852886 -240.241836)
		(end 277.452836 -240.241836)
		(width 0.101854)
		(layer "F.Cu")
		(net "M_C_CPU0_SB_CB<6>")
	)
	(segment
		(start 279.981406 -240.241836)
		(end 279.912826 -240.241836)
		(width 0.101854)
		(layer "F.Cu")
		(net "M_C_CPU0_SB_CB<6>")
	)
	(segment
		(start 281.217624 -240.946432)
		(end 280.924762 -240.946432)
		(width 0.20066)
		(layer "F.Cu")
		(net "M_C_CPU0_SB_CB<6>")
	)
	(segment
		(start 282.811982 -240.666778)
		(end 281.497278 -240.666778)
		(width 0.20066)
		(layer "F.Cu")
		(net "M_C_CPU0_SB_CB<6>")
	)
	(segment
		(start 280.689558 -240.711228)
		(end 280.689558 -240.40592)
		(width 0.20066)
		(layer "F.Cu")
		(net "M_C_CPU0_SB_CB<6>")
	)
	(segment
		(start 341.25408 -241.481102)
		(end 340.941406 -241.481102)
		(width 0.088646)
		(layer "In4.Cu")
		(net "M_C_CPU0_SB_CB<6>")
	)
	(segment
		(start 290.580318 -241.36731)
		(end 290.397438 -241.55019)
		(width 0.18288)
		(layer "In4.Cu")
		(net "M_C_CPU0_SB_CB<6>")
	)
	(segment
		(start 290.397438 -241.55019)
		(end 290.072318 -241.55019)
		(width 0.18288)
		(layer "In4.Cu")
		(net "M_C_CPU0_SB_CB<6>")
	)
	(segment
		(start 339.570568 -241.80038)
		(end 339.561678 -241.80546)
		(width 0.088646)
		(layer "In4.Cu")
		(net "M_C_CPU0_SB_CB<6>")
	)
	(segment
		(start 334.018636 -242.619276)
		(end 334.008222 -242.61318)
		(width 0.088646)
		(layer "In4.Cu")
		(net "M_C_CPU0_SB_CB<6>")
	)
	(segment
		(start 312.95086 -241.397536)
		(end 312.62574 -241.397536)
		(width 0.18288)
		(layer "In4.Cu")
		(net "M_C_CPU0_SB_CB<6>")
	)
	(segment
		(start 304.71618 -240.25479)
		(end 302.18634 -241.302794)
		(width 0.18288)
		(layer "In4.Cu")
		(net "M_C_CPU0_SB_CB<6>")
	)
	(segment
		(start 289.706558 -240.865914)
		(end 288.72434 -240.865914)
		(width 0.18288)
		(layer "In4.Cu")
		(net "M_C_CPU0_SB_CB<6>")
	)
	(segment
		(start 305.083718 -239.887252)
		(end 304.71618 -240.25479)
		(width 0.18288)
		(layer "In4.Cu")
		(net "M_C_CPU0_SB_CB<6>")
	)
	(segment
		(start 307.499004 -239.995964)
		(end 306.92852 -240.566448)
		(width 0.18288)
		(layer "In4.Cu")
		(net "M_C_CPU0_SB_CB<6>")
	)
	(segment
		(start 300.76521 -241.302794)
		(end 299.55871 -241.302794)
		(width 0.18288)
		(layer "In4.Cu")
		(net "M_C_CPU0_SB_CB<6>")
	)
	(segment
		(start 289.889438 -241.36731)
		(end 289.889438 -241.048794)
		(width 0.18288)
		(layer "In4.Cu")
		(net "M_C_CPU0_SB_CB<6>")
	)
	(segment
		(start 313.31662 -240.888266)
		(end 313.13374 -241.071146)
		(width 0.18288)
		(layer "In4.Cu")
		(net "M_C_CPU0_SB_CB<6>")
	)
	(segment
		(start 315.475112 -240.888012)
		(end 313.866276 -240.888012)
		(width 0.18288)
		(layer "In4.Cu")
		(net "M_C_CPU0_SB_CB<6>")
	)
	(segment
		(start 302.18634 -241.302794)
		(end 301.82185 -241.302794)
		(width 0.18288)
		(layer "In4.Cu")
		(net "M_C_CPU0_SB_CB<6>")
	)
	(segment
		(start 284.64891 -241.398806)
		(end 283.916882 -240.666778)
		(width 0.18288)
		(layer "In4.Cu")
		(net "M_C_CPU0_SB_CB<6>")
	)
	(segment
		(start 306.92852 -240.566448)
		(end 306.375816 -240.566448)
		(width 0.18288)
		(layer "In4.Cu")
		(net "M_C_CPU0_SB_CB<6>")
	)
	(segment
		(start 285.838646 -241.215926)
		(end 285.655766 -241.398806)
		(width 0.18288)
		(layer "In4.Cu")
		(net "M_C_CPU0_SB_CB<6>")
	)
	(segment
		(start 290.072318 -241.55019)
		(end 289.889438 -241.36731)
		(width 0.18288)
		(layer "In4.Cu")
		(net "M_C_CPU0_SB_CB<6>")
	)
	(segment
		(start 288.191448 -241.398806)
		(end 286.712406 -241.398806)
		(width 0.18288)
		(layer "In4.Cu")
		(net "M_C_CPU0_SB_CB<6>")
	)
	(segment
		(start 301.63897 -240.843054)
		(end 301.45609 -240.660174)
		(width 0.18288)
		(layer "In4.Cu")
		(net "M_C_CPU0_SB_CB<6>")
	)
	(segment
		(start 336.367882 -241.80546)
		(end 336.357468 -241.799364)
		(width 0.088646)
		(layer "In4.Cu")
		(net "M_C_CPU0_SB_CB<6>")
	)
	(segment
		(start 313.866276 -240.888012)
		(end 313.866022 -240.888266)
		(width 0.18288)
		(layer "In4.Cu")
		(net "M_C_CPU0_SB_CB<6>")
	)
	(segment
		(start 331.293724 -243.07927)
		(end 331.004418 -243.07927)
		(width 0.088646)
		(layer "In4.Cu")
		(net "M_C_CPU0_SB_CB<6>")
	)
	(segment
		(start 309.080408 -241.262916)
		(end 308.690264 -240.872772)
		(width 0.18288)
		(layer "In4.Cu")
		(net "M_C_CPU0_SB_CB<6>")
	)
	(segment
		(start 308.690264 -240.872772)
		(end 308.690264 -240.155984)
		(width 0.18288)
		(layer "In4.Cu")
		(net "M_C_CPU0_SB_CB<6>")
	)
	(segment
		(start 301.82185 -241.302794)
		(end 301.63897 -241.119914)
		(width 0.18288)
		(layer "In4.Cu")
		(net "M_C_CPU0_SB_CB<6>")
	)
	(segment
		(start 331.698346 -243.483892)
		(end 331.293724 -243.07927)
		(width 0.088646)
		(layer "In4.Cu")
		(net "M_C_CPU0_SB_CB<6>")
	)
	(segment
		(start 292.047168 -240.865914)
		(end 290.763198 -240.865914)
		(width 0.18288)
		(layer "In4.Cu")
		(net "M_C_CPU0_SB_CB<6>")
	)
	(segment
		(start 340.941406 -241.481102)
		(end 340.875874 -241.41557)
		(width 0.088646)
		(layer "In4.Cu")
		(net "M_C_CPU0_SB_CB<6>")
	)
	(segment
		(start 290.763198 -240.865914)
		(end 290.580318 -241.048794)
		(width 0.18288)
		(layer "In4.Cu")
		(net "M_C_CPU0_SB_CB<6>")
	)
	(segment
		(start 311.244742 -240.888266)
		(end 310.870092 -241.262916)
		(width 0.18288)
		(layer "In4.Cu")
		(net "M_C_CPU0_SB_CB<6>")
	)
	(segment
		(start 285.655766 -241.398806)
		(end 284.64891 -241.398806)
		(width 0.18288)
		(layer "In4.Cu")
		(net "M_C_CPU0_SB_CB<6>")
	)
	(segment
		(start 312.44286 -241.071146)
		(end 312.25998 -240.888266)
		(width 0.18288)
		(layer "In4.Cu")
		(net "M_C_CPU0_SB_CB<6>")
	)
	(segment
		(start 301.63897 -241.119914)
		(end 301.63897 -240.843054)
		(width 0.18288)
		(layer "In4.Cu")
		(net "M_C_CPU0_SB_CB<6>")
	)
	(segment
		(start 331.004418 -243.07927)
		(end 317.66637 -243.07927)
		(width 0.18288)
		(layer "In4.Cu")
		(net "M_C_CPU0_SB_CB<6>")
	)
	(segment
		(start 298.122086 -241.09172)
		(end 297.269154 -241.944652)
		(width 0.18288)
		(layer "In4.Cu")
		(net "M_C_CPU0_SB_CB<6>")
	)
	(segment
		(start 301.45609 -240.660174)
		(end 301.13097 -240.660174)
		(width 0.18288)
		(layer "In4.Cu")
		(net "M_C_CPU0_SB_CB<6>")
	)
	(segment
		(start 300.94809 -241.119914)
		(end 300.76521 -241.302794)
		(width 0.18288)
		(layer "In4.Cu")
		(net "M_C_CPU0_SB_CB<6>")
	)
	(segment
		(start 292.272974 -241.09172)
		(end 292.047168 -240.865914)
		(width 0.18288)
		(layer "In4.Cu")
		(net "M_C_CPU0_SB_CB<6>")
	)
	(segment
		(start 313.866022 -240.888266)
		(end 313.31662 -240.888266)
		(width 0.18288)
		(layer "In4.Cu")
		(net "M_C_CPU0_SB_CB<6>")
	)
	(segment
		(start 299.347636 -241.09172)
		(end 298.122086 -241.09172)
		(width 0.18288)
		(layer "In4.Cu")
		(net "M_C_CPU0_SB_CB<6>")
	)
	(segment
		(start 289.889438 -241.048794)
		(end 289.706558 -240.865914)
		(width 0.18288)
		(layer "In4.Cu")
		(net "M_C_CPU0_SB_CB<6>")
	)
	(segment
		(start 339.187282 -241.80546)
		(end 339.17255 -241.796824)
		(width 0.088646)
		(layer "In4.Cu")
		(net "M_C_CPU0_SB_CB<6>")
	)
	(segment
		(start 335.802732 -241.80546)
		(end 335.796636 -241.809016)
		(width 0.088646)
		(layer "In4.Cu")
		(net "M_C_CPU0_SB_CB<6>")
	)
	(segment
		(start 333.170784 -243.08689)
		(end 333.170784 -243.108988)
		(width 0.088646)
		(layer "In4.Cu")
		(net "M_C_CPU0_SB_CB<6>")
	)
	(segment
		(start 310.870092 -241.262916)
		(end 309.080408 -241.262916)
		(width 0.18288)
		(layer "In4.Cu")
		(net "M_C_CPU0_SB_CB<6>")
	)
	(segment
		(start 313.13374 -241.071146)
		(end 313.13374 -241.214656)
		(width 0.18288)
		(layer "In4.Cu")
		(net "M_C_CPU0_SB_CB<6>")
	)
	(segment
		(start 331.856334 -243.483892)
		(end 331.698346 -243.483892)
		(width 0.088646)
		(layer "In4.Cu")
		(net "M_C_CPU0_SB_CB<6>")
	)
	(segment
		(start 285.838646 -240.791492)
		(end 285.838646 -241.215926)
		(width 0.18288)
		(layer "In4.Cu")
		(net "M_C_CPU0_SB_CB<6>")
	)
	(segment
		(start 340.046564 -240.983008)
		(end 340.031832 -240.991644)
		(width 0.088646)
		(layer "In4.Cu")
		(net "M_C_CPU0_SB_CB<6>")
	)
	(segment
		(start 308.530244 -239.995964)
		(end 307.499004 -239.995964)
		(width 0.18288)
		(layer "In4.Cu")
		(net "M_C_CPU0_SB_CB<6>")
	)
	(segment
		(start 306.375816 -240.566448)
		(end 305.69662 -239.887252)
		(width 0.18288)
		(layer "In4.Cu")
		(net "M_C_CPU0_SB_CB<6>")
	)
	(segment
		(start 297.269154 -241.944652)
		(end 293.915846 -241.944652)
		(width 0.18288)
		(layer "In4.Cu")
		(net "M_C_CPU0_SB_CB<6>")
	)
	(segment
		(start 335.347564 -242.61064)
		(end 335.332578 -242.619276)
		(width 0.088646)
		(layer "In4.Cu")
		(net "M_C_CPU0_SB_CB<6>")
	)
	(segment
		(start 290.580318 -241.048794)
		(end 290.580318 -241.36731)
		(width 0.18288)
		(layer "In4.Cu")
		(net "M_C_CPU0_SB_CB<6>")
	)
	(segment
		(start 300.94809 -240.843054)
		(end 300.94809 -241.119914)
		(width 0.18288)
		(layer "In4.Cu")
		(net "M_C_CPU0_SB_CB<6>")
	)
	(segment
		(start 305.69662 -239.887252)
		(end 305.083718 -239.887252)
		(width 0.18288)
		(layer "In4.Cu")
		(net "M_C_CPU0_SB_CB<6>")
	)
	(segment
		(start 338.247482 -241.80546)
		(end 338.23275 -241.796824)
		(width 0.088646)
		(layer "In4.Cu")
		(net "M_C_CPU0_SB_CB<6>")
	)
	(segment
		(start 332.992222 -243.428266)
		(end 332.983332 -243.433346)
		(width 0.088646)
		(layer "In4.Cu")
		(net "M_C_CPU0_SB_CB<6>")
	)
	(segment
		(start 337.307682 -241.80546)
		(end 337.29295 -241.796824)
		(width 0.088646)
		(layer "In4.Cu")
		(net "M_C_CPU0_SB_CB<6>")
	)
	(segment
		(start 286.346646 -240.608612)
		(end 286.021526 -240.608612)
		(width 0.18288)
		(layer "In4.Cu")
		(net "M_C_CPU0_SB_CB<6>")
	)
	(segment
		(start 332.058264 -243.42471)
		(end 332.043532 -243.433346)
		(width 0.088646)
		(layer "In4.Cu")
		(net "M_C_CPU0_SB_CB<6>")
	)
	(segment
		(start 313.13374 -241.214656)
		(end 312.95086 -241.397536)
		(width 0.18288)
		(layer "In4.Cu")
		(net "M_C_CPU0_SB_CB<6>")
	)
	(segment
		(start 317.66637 -243.07927)
		(end 315.475112 -240.888012)
		(width 0.18288)
		(layer "In4.Cu")
		(net "M_C_CPU0_SB_CB<6>")
	)
	(segment
		(start 299.55871 -241.302794)
		(end 299.347636 -241.09172)
		(width 0.18288)
		(layer "In4.Cu")
		(net "M_C_CPU0_SB_CB<6>")
	)
	(segment
		(start 308.690264 -240.155984)
		(end 308.530244 -239.995964)
		(width 0.18288)
		(layer "In4.Cu")
		(net "M_C_CPU0_SB_CB<6>")
	)
	(segment
		(start 288.72434 -240.865914)
		(end 288.191448 -241.398806)
		(width 0.18288)
		(layer "In4.Cu")
		(net "M_C_CPU0_SB_CB<6>")
	)
	(segment
		(start 340.031832 -240.991644)
		(end 340.025736 -240.9952)
		(width 0.088646)
		(layer "In4.Cu")
		(net "M_C_CPU0_SB_CB<6>")
	)
	(segment
		(start 312.44286 -241.214656)
		(end 312.44286 -241.071146)
		(width 0.18288)
		(layer "In4.Cu")
		(net "M_C_CPU0_SB_CB<6>")
	)
	(segment
		(start 312.62574 -241.397536)
		(end 312.44286 -241.214656)
		(width 0.18288)
		(layer "In4.Cu")
		(net "M_C_CPU0_SB_CB<6>")
	)
	(segment
		(start 293.915846 -241.944652)
		(end 293.062914 -241.09172)
		(width 0.18288)
		(layer "In4.Cu")
		(net "M_C_CPU0_SB_CB<6>")
	)
	(segment
		(start 286.021526 -240.608612)
		(end 285.838646 -240.791492)
		(width 0.18288)
		(layer "In4.Cu")
		(net "M_C_CPU0_SB_CB<6>")
	)
	(segment
		(start 293.062914 -241.09172)
		(end 292.272974 -241.09172)
		(width 0.18288)
		(layer "In4.Cu")
		(net "M_C_CPU0_SB_CB<6>")
	)
	(segment
		(start 286.529526 -241.215926)
		(end 286.529526 -240.791492)
		(width 0.18288)
		(layer "In4.Cu")
		(net "M_C_CPU0_SB_CB<6>")
	)
	(segment
		(start 334.958182 -242.619276)
		(end 334.947768 -242.61318)
		(width 0.088646)
		(layer "In4.Cu")
		(net "M_C_CPU0_SB_CB<6>")
	)
	(segment
		(start 286.712406 -241.398806)
		(end 286.529526 -241.215926)
		(width 0.18288)
		(layer "In4.Cu")
		(net "M_C_CPU0_SB_CB<6>")
	)
	(segment
		(start 286.529526 -240.791492)
		(end 286.346646 -240.608612)
		(width 0.18288)
		(layer "In4.Cu")
		(net "M_C_CPU0_SB_CB<6>")
	)
	(segment
		(start 312.25998 -240.888266)
		(end 311.244742 -240.888266)
		(width 0.18288)
		(layer "In4.Cu")
		(net "M_C_CPU0_SB_CB<6>")
	)
	(segment
		(start 301.13097 -240.660174)
		(end 300.94809 -240.843054)
		(width 0.18288)
		(layer "In4.Cu")
		(net "M_C_CPU0_SB_CB<6>")
	)
	(arc
		(start 335.796636 -241.809016)
		(mid 335.594223 -242.015429)
		(end 335.520284 -242.294918)
		(width 0.088646)
		(layer "In4.Cu")
		(net "M_C_CPU0_SB_CB<6>")
	)
	(arc
		(start 340.597236 -240.991644)
		(mid 340.323037 -240.915809)
		(end 340.046564 -240.983008)
		(width 0.088646)
		(layer "In4.Cu")
		(net "M_C_CPU0_SB_CB<6>")
	)
	(arc
		(start 333.170784 -243.108988)
		(mid 333.123105 -243.291888)
		(end 332.992222 -243.428266)
		(width 0.088646)
		(layer "In4.Cu")
		(net "M_C_CPU0_SB_CB<6>")
	)
	(arc
		(start 339.17255 -241.796824)
		(mid 338.896075 -241.729504)
		(end 338.621878 -241.80546)
		(width 0.088646)
		(layer "In4.Cu")
		(net "M_C_CPU0_SB_CB<6>")
	)
	(arc
		(start 338.23275 -241.796824)
		(mid 337.956275 -241.729504)
		(end 337.682078 -241.80546)
		(width 0.088646)
		(layer "In4.Cu")
		(net "M_C_CPU0_SB_CB<6>")
	)
	(arc
		(start 340.875874 -241.41557)
		(mid 340.786786 -241.170585)
		(end 340.597236 -240.991644)
		(width 0.088646)
		(layer "In4.Cu")
		(net "M_C_CPU0_SB_CB<6>")
	)
	(arc
		(start 339.74913 -241.481102)
		(mid 339.701451 -241.664002)
		(end 339.570568 -241.80038)
		(width 0.088646)
		(layer "In4.Cu")
		(net "M_C_CPU0_SB_CB<6>")
	)
	(arc
		(start 334.947768 -242.61318)
		(mid 334.66959 -242.543488)
		(end 334.393032 -242.619276)
		(width 0.088646)
		(layer "In4.Cu")
		(net "M_C_CPU0_SB_CB<6>")
	)
	(arc
		(start 334.393032 -242.619276)
		(mid 334.205834 -242.669419)
		(end 334.018636 -242.619276)
		(width 0.088646)
		(layer "In4.Cu")
		(net "M_C_CPU0_SB_CB<6>")
	)
	(arc
		(start 334.008222 -242.61318)
		(mid 333.72979 -242.543366)
		(end 333.452978 -242.619276)
		(width 0.088646)
		(layer "In4.Cu")
		(net "M_C_CPU0_SB_CB<6>")
	)
	(arc
		(start 332.043532 -243.433346)
		(mid 331.95326 -243.470945)
		(end 331.856334 -243.483892)
		(width 0.088646)
		(layer "In4.Cu")
		(net "M_C_CPU0_SB_CB<6>")
	)
	(arc
		(start 332.608936 -243.433346)
		(mid 332.334737 -243.357511)
		(end 332.058264 -243.42471)
		(width 0.088646)
		(layer "In4.Cu")
		(net "M_C_CPU0_SB_CB<6>")
	)
	(arc
		(start 340.025736 -240.9952)
		(mid 339.823149 -241.201551)
		(end 339.74913 -241.481102)
		(width 0.088646)
		(layer "In4.Cu")
		(net "M_C_CPU0_SB_CB<6>")
	)
	(arc
		(start 335.520284 -242.294918)
		(mid 335.47428 -242.474855)
		(end 335.347564 -242.61064)
		(width 0.088646)
		(layer "In4.Cu")
		(net "M_C_CPU0_SB_CB<6>")
	)
	(arc
		(start 333.452978 -242.619276)
		(mid 333.251696 -242.816763)
		(end 333.170784 -243.08689)
		(width 0.088646)
		(layer "In4.Cu")
		(net "M_C_CPU0_SB_CB<6>")
	)
	(arc
		(start 338.621878 -241.80546)
		(mid 338.43468 -241.855603)
		(end 338.247482 -241.80546)
		(width 0.088646)
		(layer "In4.Cu")
		(net "M_C_CPU0_SB_CB<6>")
	)
	(arc
		(start 336.742278 -241.80546)
		(mid 336.55508 -241.855603)
		(end 336.367882 -241.80546)
		(width 0.088646)
		(layer "In4.Cu")
		(net "M_C_CPU0_SB_CB<6>")
	)
	(arc
		(start 335.332578 -242.619276)
		(mid 335.14538 -242.669419)
		(end 334.958182 -242.619276)
		(width 0.088646)
		(layer "In4.Cu")
		(net "M_C_CPU0_SB_CB<6>")
	)
	(arc
		(start 339.561678 -241.80546)
		(mid 339.37448 -241.855603)
		(end 339.187282 -241.80546)
		(width 0.088646)
		(layer "In4.Cu")
		(net "M_C_CPU0_SB_CB<6>")
	)
	(arc
		(start 337.682078 -241.80546)
		(mid 337.49488 -241.855603)
		(end 337.307682 -241.80546)
		(width 0.088646)
		(layer "In4.Cu")
		(net "M_C_CPU0_SB_CB<6>")
	)
	(arc
		(start 337.29295 -241.796824)
		(mid 337.016475 -241.729504)
		(end 336.742278 -241.80546)
		(width 0.088646)
		(layer "In4.Cu")
		(net "M_C_CPU0_SB_CB<6>")
	)
	(arc
		(start 332.983332 -243.433346)
		(mid 332.796134 -243.483489)
		(end 332.608936 -243.433346)
		(width 0.088646)
		(layer "In4.Cu")
		(net "M_C_CPU0_SB_CB<6>")
	)
	(arc
		(start 336.357468 -241.799364)
		(mid 336.07929 -241.729641)
		(end 335.802732 -241.80546)
		(width 0.088646)
		(layer "In4.Cu")
		(net "M_C_CPU0_SB_CB<6>")
	)
	(segment
		(start 276.138386 -239.391698)
		(end 274.152868 -239.391698)
		(width 0.1016)
		(layer "F.Cu")
		(net "M_C_CPU0_SB_CB<5>")
	)
	(segment
		(start 272.502376 -239.81664)
		(end 271.168114 -239.81664)
		(width 0.20066)
		(layer "F.Cu")
		(net "M_C_CPU0_SB_CB<5>")
	)
	(segment
		(start 339.84438 -241.203226)
		(end 339.844634 -241.202972)
		(width 0.20066)
		(layer "F.Cu")
		(net "M_C_CPU0_SB_CB<5>")
	)
	(segment
		(start 276.530562 -239.391698)
		(end 276.138386 -239.391698)
		(width 0.101854)
		(layer "F.Cu")
		(net "M_C_CPU0_SB_CB<5>")
	)
	(segment
		(start 273.53514 -239.391698)
		(end 273.37258 -239.554258)
		(width 0.20066)
		(layer "F.Cu")
		(net "M_C_CPU0_SB_CB<5>")
	)
	(segment
		(start 276.647656 -239.391698)
		(end 276.530562 -239.391698)
		(width 0.20066)
		(layer "F.Cu")
		(net "M_C_CPU0_SB_CB<5>")
	)
	(segment
		(start 272.713704 -240.027968)
		(end 272.502376 -239.81664)
		(width 0.20066)
		(layer "F.Cu")
		(net "M_C_CPU0_SB_CB<5>")
	)
	(segment
		(start 274.01393 -239.391698)
		(end 273.53514 -239.391698)
		(width 0.20066)
		(layer "F.Cu")
		(net "M_C_CPU0_SB_CB<5>")
	)
	(segment
		(start 273.37258 -239.873536)
		(end 273.218148 -240.027968)
		(width 0.20066)
		(layer "F.Cu")
		(net "M_C_CPU0_SB_CB<5>")
	)
	(segment
		(start 279.816814 -239.81664)
		(end 278.711914 -239.81664)
		(width 0.20066)
		(layer "F.Cu")
		(net "M_C_CPU0_SB_CB<5>")
	)
	(segment
		(start 339.844634 -241.202972)
		(end 339.844634 -240.667286)
		(width 0.20066)
		(layer "F.Cu")
		(net "M_C_CPU0_SB_CB<5>")
	)
	(segment
		(start 273.37258 -239.554258)
		(end 273.37258 -239.873536)
		(width 0.20066)
		(layer "F.Cu")
		(net "M_C_CPU0_SB_CB<5>")
	)
	(segment
		(start 277.072598 -239.81664)
		(end 276.647656 -239.391698)
		(width 0.20066)
		(layer "F.Cu")
		(net "M_C_CPU0_SB_CB<5>")
	)
	(segment
		(start 278.711914 -239.81664)
		(end 277.072598 -239.81664)
		(width 0.20066)
		(layer "F.Cu")
		(net "M_C_CPU0_SB_CB<5>")
	)
	(segment
		(start 274.152868 -239.391698)
		(end 274.01393 -239.391698)
		(width 0.101854)
		(layer "F.Cu")
		(net "M_C_CPU0_SB_CB<5>")
	)
	(segment
		(start 273.218148 -240.027968)
		(end 272.713704 -240.027968)
		(width 0.20066)
		(layer "F.Cu")
		(net "M_C_CPU0_SB_CB<5>")
	)
	(segment
		(start 336.748374 -241.160046)
		(end 336.742532 -241.156744)
		(width 0.088646)
		(layer "In4.Cu")
		(net "M_C_CPU0_SB_CB<5>")
	)
	(segment
		(start 331.362304 -242.58143)
		(end 331.004418 -242.58143)
		(width 0.088646)
		(layer "In4.Cu")
		(net "M_C_CPU0_SB_CB<5>")
	)
	(segment
		(start 282.49753 -240.81232)
		(end 282.49753 -240.424716)
		(width 0.18288)
		(layer "In4.Cu")
		(net "M_C_CPU0_SB_CB<5>")
	)
	(segment
		(start 281.29865 -240.9952)
		(end 281.11577 -240.81232)
		(width 0.18288)
		(layer "In4.Cu")
		(net "M_C_CPU0_SB_CB<5>")
	)
	(segment
		(start 281.98953 -240.241836)
		(end 281.80665 -240.424716)
		(width 0.18288)
		(layer "In4.Cu")
		(net "M_C_CPU0_SB_CB<5>")
	)
	(segment
		(start 299.701458 -240.241836)
		(end 298.171616 -240.241836)
		(width 0.18288)
		(layer "In4.Cu")
		(net "M_C_CPU0_SB_CB<5>")
	)
	(segment
		(start 334.018636 -241.97056)
		(end 334.008222 -241.976656)
		(width 0.088646)
		(layer "In4.Cu")
		(net "M_C_CPU0_SB_CB<5>")
	)
	(segment
		(start 331.85608 -242.73383)
		(end 331.514704 -242.73383)
		(width 0.088646)
		(layer "In4.Cu")
		(net "M_C_CPU0_SB_CB<5>")
	)
	(segment
		(start 309.569612 -240.122456)
		(end 308.93004 -239.482884)
		(width 0.18288)
		(layer "In4.Cu")
		(net "M_C_CPU0_SB_CB<5>")
	)
	(segment
		(start 332.058264 -242.793266)
		(end 332.043532 -242.78463)
		(width 0.088646)
		(layer "In4.Cu")
		(net "M_C_CPU0_SB_CB<5>")
	)
	(segment
		(start 283.00553 -240.9952)
		(end 282.68041 -240.9952)
		(width 0.18288)
		(layer "In4.Cu")
		(net "M_C_CPU0_SB_CB<5>")
	)
	(segment
		(start 338.627974 -241.160046)
		(end 338.61629 -241.153442)
		(width 0.088646)
		(layer "In4.Cu")
		(net "M_C_CPU0_SB_CB<5>")
	)
	(segment
		(start 334.958182 -241.97056)
		(end 334.947768 -241.976656)
		(width 0.088646)
		(layer "In4.Cu")
		(net "M_C_CPU0_SB_CB<5>")
	)
	(segment
		(start 281.11577 -240.81232)
		(end 281.11577 -240.424716)
		(width 0.18288)
		(layer "In4.Cu")
		(net "M_C_CPU0_SB_CB<5>")
	)
	(segment
		(start 313.866022 -240.375694)
		(end 311.282842 -240.375694)
		(width 0.18288)
		(layer "In4.Cu")
		(net "M_C_CPU0_SB_CB<5>")
	)
	(segment
		(start 294.023034 -241.089688)
		(end 293.175182 -240.241836)
		(width 0.18288)
		(layer "In4.Cu")
		(net "M_C_CPU0_SB_CB<5>")
	)
	(segment
		(start 288.775648 -240.365026)
		(end 288.487358 -240.076736)
		(width 0.18288)
		(layer "In4.Cu")
		(net "M_C_CPU0_SB_CB<5>")
	)
	(segment
		(start 303.81702 -239.293908)
		(end 302.983138 -240.12779)
		(width 0.18288)
		(layer "In4.Cu")
		(net "M_C_CPU0_SB_CB<5>")
	)
	(segment
		(start 291.88664 -240.241836)
		(end 291.76345 -240.365026)
		(width 0.18288)
		(layer "In4.Cu")
		(net "M_C_CPU0_SB_CB<5>")
	)
	(segment
		(start 336.367882 -241.156744)
		(end 336.357468 -241.16284)
		(width 0.088646)
		(layer "In4.Cu")
		(net "M_C_CPU0_SB_CB<5>")
	)
	(segment
		(start 337.688174 -241.160046)
		(end 337.67649 -241.153442)
		(width 0.088646)
		(layer "In4.Cu")
		(net "M_C_CPU0_SB_CB<5>")
	)
	(segment
		(start 335.428336 -241.156744)
		(end 335.419446 -241.161824)
		(width 0.088646)
		(layer "In4.Cu")
		(net "M_C_CPU0_SB_CB<5>")
	)
	(segment
		(start 281.80665 -240.81232)
		(end 281.62377 -240.9952)
		(width 0.18288)
		(layer "In4.Cu")
		(net "M_C_CPU0_SB_CB<5>")
	)
	(segment
		(start 291.76345 -240.365026)
		(end 288.775648 -240.365026)
		(width 0.18288)
		(layer "In4.Cu")
		(net "M_C_CPU0_SB_CB<5>")
	)
	(segment
		(start 284.582108 -240.241836)
		(end 283.37129 -240.241836)
		(width 0.18288)
		(layer "In4.Cu")
		(net "M_C_CPU0_SB_CB<5>")
	)
	(segment
		(start 317.87465 -242.58143)
		(end 315.66866 -240.37544)
		(width 0.18288)
		(layer "In4.Cu")
		(net "M_C_CPU0_SB_CB<5>")
	)
	(segment
		(start 311.282842 -240.375694)
		(end 311.029604 -240.122456)
		(width 0.18288)
		(layer "In4.Cu")
		(net "M_C_CPU0_SB_CB<5>")
	)
	(segment
		(start 334.964278 -241.967004)
		(end 334.958182 -241.97056)
		(width 0.088646)
		(layer "In4.Cu")
		(net "M_C_CPU0_SB_CB<5>")
	)
	(segment
		(start 311.029604 -240.122456)
		(end 309.569612 -240.122456)
		(width 0.18288)
		(layer "In4.Cu")
		(net "M_C_CPU0_SB_CB<5>")
	)
	(segment
		(start 281.62377 -240.9952)
		(end 281.29865 -240.9952)
		(width 0.18288)
		(layer "In4.Cu")
		(net "M_C_CPU0_SB_CB<5>")
	)
	(segment
		(start 282.31465 -240.241836)
		(end 281.98953 -240.241836)
		(width 0.18288)
		(layer "In4.Cu")
		(net "M_C_CPU0_SB_CB<5>")
	)
	(segment
		(start 297.323764 -241.089688)
		(end 294.023034 -241.089688)
		(width 0.18288)
		(layer "In4.Cu")
		(net "M_C_CPU0_SB_CB<5>")
	)
	(segment
		(start 288.487358 -240.076736)
		(end 284.747208 -240.076736)
		(width 0.18288)
		(layer "In4.Cu")
		(net "M_C_CPU0_SB_CB<5>")
	)
	(segment
		(start 284.747208 -240.076736)
		(end 284.582108 -240.241836)
		(width 0.18288)
		(layer "In4.Cu")
		(net "M_C_CPU0_SB_CB<5>")
	)
	(segment
		(start 336.742532 -241.156744)
		(end 336.738722 -241.154458)
		(width 0.088646)
		(layer "In4.Cu")
		(net "M_C_CPU0_SB_CB<5>")
	)
	(segment
		(start 307.192172 -239.482884)
		(end 307.003196 -239.293908)
		(width 0.18288)
		(layer "In4.Cu")
		(net "M_C_CPU0_SB_CB<5>")
	)
	(segment
		(start 308.93004 -239.482884)
		(end 307.192172 -239.482884)
		(width 0.18288)
		(layer "In4.Cu")
		(net "M_C_CPU0_SB_CB<5>")
	)
	(segment
		(start 283.18841 -240.81232)
		(end 283.00553 -240.9952)
		(width 0.18288)
		(layer "In4.Cu")
		(net "M_C_CPU0_SB_CB<5>")
	)
	(segment
		(start 315.66866 -240.37544)
		(end 313.866276 -240.37544)
		(width 0.18288)
		(layer "In4.Cu")
		(net "M_C_CPU0_SB_CB<5>")
	)
	(segment
		(start 281.80665 -240.424716)
		(end 281.80665 -240.81232)
		(width 0.18288)
		(layer "In4.Cu")
		(net "M_C_CPU0_SB_CB<5>")
	)
	(segment
		(start 339.263482 -241.112802)
		(end 339.187282 -241.156744)
		(width 0.088646)
		(layer "In4.Cu")
		(net "M_C_CPU0_SB_CB<5>")
	)
	(segment
		(start 313.866276 -240.37544)
		(end 313.866022 -240.375694)
		(width 0.18288)
		(layer "In4.Cu")
		(net "M_C_CPU0_SB_CB<5>")
	)
	(segment
		(start 282.68041 -240.9952)
		(end 282.49753 -240.81232)
		(width 0.18288)
		(layer "In4.Cu")
		(net "M_C_CPU0_SB_CB<5>")
	)
	(segment
		(start 280.24201 -240.241836)
		(end 279.816814 -239.81664)
		(width 0.18288)
		(layer "In4.Cu")
		(net "M_C_CPU0_SB_CB<5>")
	)
	(segment
		(start 331.514704 -242.73383)
		(end 331.362304 -242.58143)
		(width 0.088646)
		(layer "In4.Cu")
		(net "M_C_CPU0_SB_CB<5>")
	)
	(segment
		(start 307.003196 -239.293908)
		(end 303.81702 -239.293908)
		(width 0.18288)
		(layer "In4.Cu")
		(net "M_C_CPU0_SB_CB<5>")
	)
	(segment
		(start 299.815504 -240.12779)
		(end 299.701458 -240.241836)
		(width 0.18288)
		(layer "In4.Cu")
		(net "M_C_CPU0_SB_CB<5>")
	)
	(segment
		(start 281.11577 -240.424716)
		(end 280.93289 -240.241836)
		(width 0.18288)
		(layer "In4.Cu")
		(net "M_C_CPU0_SB_CB<5>")
	)
	(segment
		(start 331.004418 -242.58143)
		(end 317.87465 -242.58143)
		(width 0.18288)
		(layer "In4.Cu")
		(net "M_C_CPU0_SB_CB<5>")
	)
	(segment
		(start 333.078582 -241.97056)
		(end 333.069692 -241.97564)
		(width 0.088646)
		(layer "In4.Cu")
		(net "M_C_CPU0_SB_CB<5>")
	)
	(segment
		(start 280.93289 -240.241836)
		(end 280.24201 -240.241836)
		(width 0.18288)
		(layer "In4.Cu")
		(net "M_C_CPU0_SB_CB<5>")
	)
	(segment
		(start 282.49753 -240.424716)
		(end 282.31465 -240.241836)
		(width 0.18288)
		(layer "In4.Cu")
		(net "M_C_CPU0_SB_CB<5>")
	)
	(segment
		(start 302.983138 -240.12779)
		(end 299.815504 -240.12779)
		(width 0.18288)
		(layer "In4.Cu")
		(net "M_C_CPU0_SB_CB<5>")
	)
	(segment
		(start 283.37129 -240.241836)
		(end 283.18841 -240.424716)
		(width 0.18288)
		(layer "In4.Cu")
		(net "M_C_CPU0_SB_CB<5>")
	)
	(segment
		(start 293.175182 -240.241836)
		(end 291.88664 -240.241836)
		(width 0.18288)
		(layer "In4.Cu")
		(net "M_C_CPU0_SB_CB<5>")
	)
	(segment
		(start 332.89113 -242.294918)
		(end 332.89113 -242.317016)
		(width 0.088646)
		(layer "In4.Cu")
		(net "M_C_CPU0_SB_CB<5>")
	)
	(segment
		(start 298.171616 -240.241836)
		(end 297.323764 -241.089688)
		(width 0.18288)
		(layer "In4.Cu")
		(net "M_C_CPU0_SB_CB<5>")
	)
	(segment
		(start 283.18841 -240.424716)
		(end 283.18841 -240.81232)
		(width 0.18288)
		(layer "In4.Cu")
		(net "M_C_CPU0_SB_CB<5>")
	)
	(arc
		(start 334.947768 -241.976656)
		(mid 334.66959 -242.046379)
		(end 334.393032 -241.97056)
		(width 0.088646)
		(layer "In4.Cu")
		(net "M_C_CPU0_SB_CB<5>")
	)
	(arc
		(start 335.240884 -241.481102)
		(mid 335.166893 -241.760668)
		(end 334.964278 -241.967004)
		(width 0.088646)
		(layer "In4.Cu")
		(net "M_C_CPU0_SB_CB<5>")
	)
	(arc
		(start 332.608936 -242.78463)
		(mid 332.334707 -242.860555)
		(end 332.058264 -242.793266)
		(width 0.088646)
		(layer "In4.Cu")
		(net "M_C_CPU0_SB_CB<5>")
	)
	(arc
		(start 336.738722 -241.154458)
		(mid 336.553003 -241.106506)
		(end 336.367882 -241.156744)
		(width 0.088646)
		(layer "In4.Cu")
		(net "M_C_CPU0_SB_CB<5>")
	)
	(arc
		(start 333.452978 -241.97056)
		(mid 333.26578 -241.920417)
		(end 333.078582 -241.97056)
		(width 0.088646)
		(layer "In4.Cu")
		(net "M_C_CPU0_SB_CB<5>")
	)
	(arc
		(start 338.247482 -241.156744)
		(mid 337.968279 -241.232384)
		(end 337.688174 -241.160046)
		(width 0.088646)
		(layer "In4.Cu")
		(net "M_C_CPU0_SB_CB<5>")
	)
	(arc
		(start 339.844634 -240.667286)
		(mid 339.568731 -240.909185)
		(end 339.263482 -241.112802)
		(width 0.088646)
		(layer "In4.Cu")
		(net "M_C_CPU0_SB_CB<5>")
	)
	(arc
		(start 336.357468 -241.16284)
		(mid 336.07929 -241.232563)
		(end 335.802732 -241.156744)
		(width 0.088646)
		(layer "In4.Cu")
		(net "M_C_CPU0_SB_CB<5>")
	)
	(arc
		(start 333.069692 -241.97564)
		(mid 332.938778 -242.112)
		(end 332.89113 -242.294918)
		(width 0.088646)
		(layer "In4.Cu")
		(net "M_C_CPU0_SB_CB<5>")
	)
	(arc
		(start 337.307682 -241.156744)
		(mid 337.028479 -241.232384)
		(end 336.748374 -241.160046)
		(width 0.088646)
		(layer "In4.Cu")
		(net "M_C_CPU0_SB_CB<5>")
	)
	(arc
		(start 335.419446 -241.161824)
		(mid 335.288532 -241.298184)
		(end 335.240884 -241.481102)
		(width 0.088646)
		(layer "In4.Cu")
		(net "M_C_CPU0_SB_CB<5>")
	)
	(arc
		(start 334.393032 -241.97056)
		(mid 334.205834 -241.920417)
		(end 334.018636 -241.97056)
		(width 0.088646)
		(layer "In4.Cu")
		(net "M_C_CPU0_SB_CB<5>")
	)
	(arc
		(start 332.043532 -242.78463)
		(mid 331.953153 -242.746875)
		(end 331.85608 -242.73383)
		(width 0.088646)
		(layer "In4.Cu")
		(net "M_C_CPU0_SB_CB<5>")
	)
	(arc
		(start 337.67649 -241.153442)
		(mid 337.491635 -241.106492)
		(end 337.307682 -241.156744)
		(width 0.088646)
		(layer "In4.Cu")
		(net "M_C_CPU0_SB_CB<5>")
	)
	(arc
		(start 338.61629 -241.153442)
		(mid 338.431435 -241.106492)
		(end 338.247482 -241.156744)
		(width 0.088646)
		(layer "In4.Cu")
		(net "M_C_CPU0_SB_CB<5>")
	)
	(arc
		(start 335.802732 -241.156744)
		(mid 335.615534 -241.106601)
		(end 335.428336 -241.156744)
		(width 0.088646)
		(layer "In4.Cu")
		(net "M_C_CPU0_SB_CB<5>")
	)
	(arc
		(start 334.008222 -241.976656)
		(mid 333.72979 -242.046502)
		(end 333.452978 -241.97056)
		(width 0.088646)
		(layer "In4.Cu")
		(net "M_C_CPU0_SB_CB<5>")
	)
	(arc
		(start 332.89113 -242.317016)
		(mid 332.810219 -242.587144)
		(end 332.608936 -242.78463)
		(width 0.088646)
		(layer "In4.Cu")
		(net "M_C_CPU0_SB_CB<5>")
	)
	(arc
		(start 339.187282 -241.156744)
		(mid 338.908079 -241.232384)
		(end 338.627974 -241.160046)
		(width 0.088646)
		(layer "In4.Cu")
		(net "M_C_CPU0_SB_CB<5>")
	)
	(segment
		(start 340.31428 -242.016788)
		(end 340.31428 -241.481102)
		(width 0.20066)
		(layer "F.Cu")
		(net "M_C_CPU0_SB_CB<4>")
	)
	(segment
		(start 276.53869 -241.09172)
		(end 276.469094 -241.09172)
		(width 0.101854)
		(layer "F.Cu")
		(net "M_C_CPU0_SB_CB<4>")
	)
	(segment
		(start 340.314534 -242.017042)
		(end 340.31428 -242.016788)
		(width 0.20066)
		(layer "F.Cu")
		(net "M_C_CPU0_SB_CB<4>")
	)
	(segment
		(start 274.40001 -241.09172)
		(end 274.009866 -241.09172)
		(width 0.101854)
		(layer "F.Cu")
		(net "M_C_CPU0_SB_CB<4>")
	)
	(segment
		(start 272.502376 -241.516662)
		(end 271.168114 -241.516662)
		(width 0.20066)
		(layer "F.Cu")
		(net "M_C_CPU0_SB_CB<4>")
	)
	(segment
		(start 277.342854 -241.516662)
		(end 276.917912 -241.09172)
		(width 0.20066)
		(layer "F.Cu")
		(net "M_C_CPU0_SB_CB<4>")
	)
	(segment
		(start 273.574002 -241.09172)
		(end 273.37258 -241.293142)
		(width 0.20066)
		(layer "F.Cu")
		(net "M_C_CPU0_SB_CB<4>")
	)
	(segment
		(start 276.469094 -241.09172)
		(end 274.40001 -241.09172)
		(width 0.1016)
		(layer "F.Cu")
		(net "M_C_CPU0_SB_CB<4>")
	)
	(segment
		(start 272.741136 -241.755422)
		(end 272.502376 -241.516662)
		(width 0.20066)
		(layer "F.Cu")
		(net "M_C_CPU0_SB_CB<4>")
	)
	(segment
		(start 273.19986 -241.755422)
		(end 272.741136 -241.755422)
		(width 0.20066)
		(layer "F.Cu")
		(net "M_C_CPU0_SB_CB<4>")
	)
	(segment
		(start 274.009866 -241.09172)
		(end 273.574002 -241.09172)
		(width 0.20066)
		(layer "F.Cu")
		(net "M_C_CPU0_SB_CB<4>")
	)
	(segment
		(start 273.37258 -241.582702)
		(end 273.19986 -241.755422)
		(width 0.20066)
		(layer "F.Cu")
		(net "M_C_CPU0_SB_CB<4>")
	)
	(segment
		(start 273.37258 -241.293142)
		(end 273.37258 -241.582702)
		(width 0.20066)
		(layer "F.Cu")
		(net "M_C_CPU0_SB_CB<4>")
	)
	(segment
		(start 278.711914 -241.516662)
		(end 277.342854 -241.516662)
		(width 0.20066)
		(layer "F.Cu")
		(net "M_C_CPU0_SB_CB<4>")
	)
	(segment
		(start 276.917912 -241.09172)
		(end 276.53869 -241.09172)
		(width 0.20066)
		(layer "F.Cu")
		(net "M_C_CPU0_SB_CB<4>")
	)
	(segment
		(start 279.816814 -241.516662)
		(end 278.711914 -241.516662)
		(width 0.20066)
		(layer "F.Cu")
		(net "M_C_CPU0_SB_CB<4>")
	)
	(segment
		(start 282.26766 -242.472972)
		(end 282.10764 -242.632992)
		(width 0.18288)
		(layer "In4.Cu")
		(net "M_C_CPU0_SB_CB<4>")
	)
	(segment
		(start 311.177686 -241.940842)
		(end 311.041288 -241.940842)
		(width 0.18288)
		(layer "In4.Cu")
		(net "M_C_CPU0_SB_CB<4>")
	)
	(segment
		(start 298.401994 -241.941858)
		(end 297.89374 -242.450112)
		(width 0.18288)
		(layer "In4.Cu")
		(net "M_C_CPU0_SB_CB<4>")
	)
	(segment
		(start 339.106764 -241.979196)
		(end 339.092032 -241.97056)
		(width 0.088646)
		(layer "In4.Cu")
		(net "M_C_CPU0_SB_CB<4>")
	)
	(segment
		(start 282.10764 -242.632992)
		(end 281.73426 -242.632992)
		(width 0.18288)
		(layer "In4.Cu")
		(net "M_C_CPU0_SB_CB<4>")
	)
	(segment
		(start 340.510368 -241.161824)
		(end 340.501478 -241.156744)
		(width 0.088646)
		(layer "In4.Cu")
		(net "M_C_CPU0_SB_CB<4>")
	)
	(segment
		(start 340.31428 -241.481102)
		(end 340.626954 -241.481102)
		(width 0.088646)
		(layer "In4.Cu")
		(net "M_C_CPU0_SB_CB<4>")
	)
	(segment
		(start 333.084678 -243.59489)
		(end 333.078582 -243.598446)
		(width 0.088646)
		(layer "In4.Cu")
		(net "M_C_CPU0_SB_CB<4>")
	)
	(segment
		(start 315.797946 -241.941858)
		(end 311.178702 -241.941858)
		(width 0.18288)
		(layer "In4.Cu")
		(net "M_C_CPU0_SB_CB<4>")
	)
	(segment
		(start 290.656518 -242.373658)
		(end 288.294572 -242.373658)
		(width 0.18288)
		(layer "In4.Cu")
		(net "M_C_CPU0_SB_CB<4>")
	)
	(segment
		(start 331.004418 -243.57711)
		(end 317.433198 -243.57711)
		(width 0.18288)
		(layer "In4.Cu")
		(net "M_C_CPU0_SB_CB<4>")
	)
	(segment
		(start 336.287364 -241.979196)
		(end 336.272632 -241.97056)
		(width 0.088646)
		(layer "In4.Cu")
		(net "M_C_CPU0_SB_CB<4>")
	)
	(segment
		(start 282.26766 -242.101878)
		(end 282.26766 -242.472972)
		(width 0.18288)
		(layer "In4.Cu")
		(net "M_C_CPU0_SB_CB<4>")
	)
	(segment
		(start 287.862772 -241.941858)
		(end 282.42768 -241.941858)
		(width 0.18288)
		(layer "In4.Cu")
		(net "M_C_CPU0_SB_CB<4>")
	)
	(segment
		(start 280.24201 -241.941858)
		(end 279.816814 -241.516662)
		(width 0.18288)
		(layer "In4.Cu")
		(net "M_C_CPU0_SB_CB<4>")
	)
	(segment
		(start 311.178702 -241.941858)
		(end 311.177686 -241.940842)
		(width 0.18288)
		(layer "In4.Cu")
		(net "M_C_CPU0_SB_CB<4>")
	)
	(segment
		(start 307.765704 -241.093752)
		(end 304.111152 -241.093752)
		(width 0.18288)
		(layer "In4.Cu")
		(net "M_C_CPU0_SB_CB<4>")
	)
	(segment
		(start 304.111152 -241.093752)
		(end 302.063912 -241.941858)
		(width 0.18288)
		(layer "In4.Cu")
		(net "M_C_CPU0_SB_CB<4>")
	)
	(segment
		(start 335.710784 -242.294918)
		(end 335.710784 -242.309142)
		(width 0.088646)
		(layer "In4.Cu")
		(net "M_C_CPU0_SB_CB<4>")
	)
	(segment
		(start 338.166964 -241.979196)
		(end 338.152232 -241.97056)
		(width 0.088646)
		(layer "In4.Cu")
		(net "M_C_CPU0_SB_CB<4>")
	)
	(segment
		(start 282.42768 -241.941858)
		(end 282.26766 -242.101878)
		(width 0.18288)
		(layer "In4.Cu")
		(net "M_C_CPU0_SB_CB<4>")
	)
	(segment
		(start 311.041288 -241.940842)
		(end 311.039764 -241.942366)
		(width 0.18288)
		(layer "In4.Cu")
		(net "M_C_CPU0_SB_CB<4>")
	)
	(segment
		(start 293.4335 -242.445032)
		(end 292.930326 -241.941858)
		(width 0.18288)
		(layer "In4.Cu")
		(net "M_C_CPU0_SB_CB<4>")
	)
	(segment
		(start 331.856588 -243.674138)
		(end 331.523848 -243.674138)
		(width 0.088646)
		(layer "In4.Cu")
		(net "M_C_CPU0_SB_CB<4>")
	)
	(segment
		(start 281.57424 -242.101878)
		(end 281.41422 -241.941858)
		(width 0.18288)
		(layer "In4.Cu")
		(net "M_C_CPU0_SB_CB<4>")
	)
	(segment
		(start 340.626954 -241.481102)
		(end 340.684358 -241.423698)
		(width 0.088646)
		(layer "In4.Cu")
		(net "M_C_CPU0_SB_CB<4>")
	)
	(segment
		(start 292.930326 -241.941858)
		(end 291.984938 -241.941858)
		(width 0.18288)
		(layer "In4.Cu")
		(net "M_C_CPU0_SB_CB<4>")
	)
	(segment
		(start 331.42682 -243.57711)
		(end 331.004418 -243.57711)
		(width 0.088646)
		(layer "In4.Cu")
		(net "M_C_CPU0_SB_CB<4>")
	)
	(segment
		(start 297.89374 -242.450112)
		(end 295.50868 -242.450112)
		(width 0.18288)
		(layer "In4.Cu")
		(net "M_C_CPU0_SB_CB<4>")
	)
	(segment
		(start 335.898236 -241.97056)
		(end 335.89849 -241.97056)
		(width 0.088646)
		(layer "In4.Cu")
		(net "M_C_CPU0_SB_CB<4>")
	)
	(segment
		(start 331.523848 -243.674138)
		(end 331.42682 -243.57711)
		(width 0.088646)
		(layer "In4.Cu")
		(net "M_C_CPU0_SB_CB<4>")
	)
	(segment
		(start 281.57424 -242.472972)
		(end 281.57424 -242.101878)
		(width 0.18288)
		(layer "In4.Cu")
		(net "M_C_CPU0_SB_CB<4>")
	)
	(segment
		(start 281.73426 -242.632992)
		(end 281.57424 -242.472972)
		(width 0.18288)
		(layer "In4.Cu")
		(net "M_C_CPU0_SB_CB<4>")
	)
	(segment
		(start 288.294572 -242.373658)
		(end 287.862772 -241.941858)
		(width 0.18288)
		(layer "In4.Cu")
		(net "M_C_CPU0_SB_CB<4>")
	)
	(segment
		(start 291.088826 -241.942366)
		(end 291.088318 -241.941858)
		(width 0.18288)
		(layer "In4.Cu")
		(net "M_C_CPU0_SB_CB<4>")
	)
	(segment
		(start 339.93963 -241.481102)
		(end 339.93963 -241.496596)
		(width 0.088646)
		(layer "In4.Cu")
		(net "M_C_CPU0_SB_CB<4>")
	)
	(segment
		(start 302.063912 -241.941858)
		(end 298.401994 -241.941858)
		(width 0.18288)
		(layer "In4.Cu")
		(net "M_C_CPU0_SB_CB<4>")
	)
	(segment
		(start 295.16705 -242.791742)
		(end 294.70731 -242.791742)
		(width 0.18288)
		(layer "In4.Cu")
		(net "M_C_CPU0_SB_CB<4>")
	)
	(segment
		(start 295.50868 -242.450112)
		(end 295.16705 -242.791742)
		(width 0.18288)
		(layer "In4.Cu")
		(net "M_C_CPU0_SB_CB<4>")
	)
	(segment
		(start 317.433198 -243.57711)
		(end 315.797946 -241.941858)
		(width 0.18288)
		(layer "In4.Cu")
		(net "M_C_CPU0_SB_CB<4>")
	)
	(segment
		(start 294.70731 -242.791742)
		(end 294.3606 -242.445032)
		(width 0.18288)
		(layer "In4.Cu")
		(net "M_C_CPU0_SB_CB<4>")
	)
	(segment
		(start 340.127082 -241.156744)
		(end 340.118192 -241.161824)
		(width 0.088646)
		(layer "In4.Cu")
		(net "M_C_CPU0_SB_CB<4>")
	)
	(segment
		(start 291.98443 -241.942366)
		(end 291.088826 -241.942366)
		(width 0.18288)
		(layer "In4.Cu")
		(net "M_C_CPU0_SB_CB<4>")
	)
	(segment
		(start 333.548736 -242.78463)
		(end 333.539846 -242.78971)
		(width 0.088646)
		(layer "In4.Cu")
		(net "M_C_CPU0_SB_CB<4>")
	)
	(segment
		(start 311.039764 -241.942366)
		(end 308.614318 -241.942366)
		(width 0.18288)
		(layer "In4.Cu")
		(net "M_C_CPU0_SB_CB<4>")
	)
	(segment
		(start 308.614318 -241.942366)
		(end 307.765704 -241.093752)
		(width 0.18288)
		(layer "In4.Cu")
		(net "M_C_CPU0_SB_CB<4>")
	)
	(segment
		(start 337.227164 -241.979196)
		(end 337.212432 -241.97056)
		(width 0.088646)
		(layer "In4.Cu")
		(net "M_C_CPU0_SB_CB<4>")
	)
	(segment
		(start 333.078582 -243.598446)
		(end 333.06385 -243.607082)
		(width 0.088646)
		(layer "In4.Cu")
		(net "M_C_CPU0_SB_CB<4>")
	)
	(segment
		(start 281.41422 -241.941858)
		(end 280.24201 -241.941858)
		(width 0.18288)
		(layer "In4.Cu")
		(net "M_C_CPU0_SB_CB<4>")
	)
	(segment
		(start 291.984938 -241.941858)
		(end 291.98443 -241.942366)
		(width 0.18288)
		(layer "In4.Cu")
		(net "M_C_CPU0_SB_CB<4>")
	)
	(segment
		(start 335.89849 -241.97056)
		(end 335.883504 -241.979196)
		(width 0.088646)
		(layer "In4.Cu")
		(net "M_C_CPU0_SB_CB<4>")
	)
	(segment
		(start 294.3606 -242.445032)
		(end 293.4335 -242.445032)
		(width 0.18288)
		(layer "In4.Cu")
		(net "M_C_CPU0_SB_CB<4>")
	)
	(segment
		(start 334.877664 -242.793266)
		(end 334.862932 -242.78463)
		(width 0.088646)
		(layer "In4.Cu")
		(net "M_C_CPU0_SB_CB<4>")
	)
	(segment
		(start 291.088318 -241.941858)
		(end 290.656518 -242.373658)
		(width 0.18288)
		(layer "In4.Cu")
		(net "M_C_CPU0_SB_CB<4>")
	)
	(arc
		(start 333.923132 -242.78463)
		(mid 333.735934 -242.734487)
		(end 333.548736 -242.78463)
		(width 0.088646)
		(layer "In4.Cu")
		(net "M_C_CPU0_SB_CB<4>")
	)
	(arc
		(start 331.89291 -243.673122)
		(mid 331.874757 -243.673925)
		(end 331.856588 -243.674138)
		(width 0.088646)
		(layer "In4.Cu")
		(net "M_C_CPU0_SB_CB<4>")
	)
	(arc
		(start 334.488536 -242.78463)
		(mid 334.205834 -242.860372)
		(end 333.923132 -242.78463)
		(width 0.088646)
		(layer "In4.Cu")
		(net "M_C_CPU0_SB_CB<4>")
	)
	(arc
		(start 339.93963 -241.496596)
		(mid 339.86026 -241.77033)
		(end 339.657436 -241.97056)
		(width 0.088646)
		(layer "In4.Cu")
		(net "M_C_CPU0_SB_CB<4>")
	)
	(arc
		(start 340.684358 -241.423698)
		(mid 340.626202 -241.273585)
		(end 340.510368 -241.161824)
		(width 0.088646)
		(layer "In4.Cu")
		(net "M_C_CPU0_SB_CB<4>")
	)
	(arc
		(start 336.838036 -241.97056)
		(mid 336.563837 -242.046395)
		(end 336.287364 -241.979196)
		(width 0.088646)
		(layer "In4.Cu")
		(net "M_C_CPU0_SB_CB<4>")
	)
	(arc
		(start 338.152232 -241.97056)
		(mid 337.965034 -241.920417)
		(end 337.777836 -241.97056)
		(width 0.088646)
		(layer "In4.Cu")
		(net "M_C_CPU0_SB_CB<4>")
	)
	(arc
		(start 337.777836 -241.97056)
		(mid 337.503637 -242.046395)
		(end 337.227164 -241.979196)
		(width 0.088646)
		(layer "In4.Cu")
		(net "M_C_CPU0_SB_CB<4>")
	)
	(arc
		(start 333.539846 -242.78971)
		(mid 333.408932 -242.92607)
		(end 333.361284 -243.108988)
		(width 0.088646)
		(layer "In4.Cu")
		(net "M_C_CPU0_SB_CB<4>")
	)
	(arc
		(start 335.428336 -242.78463)
		(mid 335.154107 -242.860555)
		(end 334.877664 -242.793266)
		(width 0.088646)
		(layer "In4.Cu")
		(net "M_C_CPU0_SB_CB<4>")
	)
	(arc
		(start 332.138782 -243.598446)
		(mid 332.020151 -243.649966)
		(end 331.89291 -243.673122)
		(width 0.088646)
		(layer "In4.Cu")
		(net "M_C_CPU0_SB_CB<4>")
	)
	(arc
		(start 336.272632 -241.97056)
		(mid 336.085434 -241.920417)
		(end 335.898236 -241.97056)
		(width 0.088646)
		(layer "In4.Cu")
		(net "M_C_CPU0_SB_CB<4>")
	)
	(arc
		(start 339.657436 -241.97056)
		(mid 339.383237 -242.046395)
		(end 339.106764 -241.979196)
		(width 0.088646)
		(layer "In4.Cu")
		(net "M_C_CPU0_SB_CB<4>")
	)
	(arc
		(start 340.118192 -241.161824)
		(mid 339.987278 -241.298184)
		(end 339.93963 -241.481102)
		(width 0.088646)
		(layer "In4.Cu")
		(net "M_C_CPU0_SB_CB<4>")
	)
	(arc
		(start 335.710784 -242.309142)
		(mid 335.631643 -242.583765)
		(end 335.428336 -242.78463)
		(width 0.088646)
		(layer "In4.Cu")
		(net "M_C_CPU0_SB_CB<4>")
	)
	(arc
		(start 335.883504 -241.979196)
		(mid 335.756781 -242.114977)
		(end 335.710784 -242.294918)
		(width 0.088646)
		(layer "In4.Cu")
		(net "M_C_CPU0_SB_CB<4>")
	)
	(arc
		(start 338.717636 -241.97056)
		(mid 338.443437 -242.046395)
		(end 338.166964 -241.979196)
		(width 0.088646)
		(layer "In4.Cu")
		(net "M_C_CPU0_SB_CB<4>")
	)
	(arc
		(start 339.092032 -241.97056)
		(mid 338.904834 -241.920417)
		(end 338.717636 -241.97056)
		(width 0.088646)
		(layer "In4.Cu")
		(net "M_C_CPU0_SB_CB<4>")
	)
	(arc
		(start 334.862932 -242.78463)
		(mid 334.675734 -242.734487)
		(end 334.488536 -242.78463)
		(width 0.088646)
		(layer "In4.Cu")
		(net "M_C_CPU0_SB_CB<4>")
	)
	(arc
		(start 333.06385 -243.607082)
		(mid 332.787375 -243.674402)
		(end 332.513178 -243.598446)
		(width 0.088646)
		(layer "In4.Cu")
		(net "M_C_CPU0_SB_CB<4>")
	)
	(arc
		(start 340.501478 -241.156744)
		(mid 340.31428 -241.106601)
		(end 340.127082 -241.156744)
		(width 0.088646)
		(layer "In4.Cu")
		(net "M_C_CPU0_SB_CB<4>")
	)
	(arc
		(start 333.361284 -243.108988)
		(mid 333.287293 -243.388554)
		(end 333.084678 -243.59489)
		(width 0.088646)
		(layer "In4.Cu")
		(net "M_C_CPU0_SB_CB<4>")
	)
	(arc
		(start 332.513178 -243.598446)
		(mid 332.32598 -243.548303)
		(end 332.138782 -243.598446)
		(width 0.088646)
		(layer "In4.Cu")
		(net "M_C_CPU0_SB_CB<4>")
	)
	(arc
		(start 337.212432 -241.97056)
		(mid 337.025234 -241.920417)
		(end 336.838036 -241.97056)
		(width 0.088646)
		(layer "In4.Cu")
		(net "M_C_CPU0_SB_CB<4>")
	)
	(segment
		(start 280.800556 -232.916222)
		(end 280.606246 -233.110532)
		(width 0.20066)
		(layer "F.Cu")
		(net "M_C_CPU0_SB_CB<3>")
	)
	(segment
		(start 281.084528 -232.916222)
		(end 280.800556 -232.916222)
		(width 0.20066)
		(layer "F.Cu")
		(net "M_C_CPU0_SB_CB<3>")
	)
	(segment
		(start 279.912826 -233.441748)
		(end 277.839932 -233.441748)
		(width 0.1016)
		(layer "F.Cu")
		(net "M_C_CPU0_SB_CB<3>")
	)
	(segment
		(start 341.254334 -238.761524)
		(end 341.25408 -238.76127)
		(width 0.20066)
		(layer "F.Cu")
		(net "M_C_CPU0_SB_CB<3>")
	)
	(segment
		(start 277.839932 -233.441748)
		(end 277.456646 -233.441748)
		(width 0.101854)
		(layer "F.Cu")
		(net "M_C_CPU0_SB_CB<3>")
	)
	(segment
		(start 341.25408 -238.76127)
		(end 341.25408 -238.225584)
		(width 0.20066)
		(layer "F.Cu")
		(net "M_C_CPU0_SB_CB<3>")
	)
	(segment
		(start 276.96541 -233.016806)
		(end 275.268182 -233.016806)
		(width 0.20066)
		(layer "F.Cu")
		(net "M_C_CPU0_SB_CB<3>")
	)
	(segment
		(start 280.606246 -233.110532)
		(end 280.606246 -233.29265)
		(width 0.20066)
		(layer "F.Cu")
		(net "M_C_CPU0_SB_CB<3>")
	)
	(segment
		(start 277.233888 -233.441748)
		(end 277.091394 -233.299254)
		(width 0.20066)
		(layer "F.Cu")
		(net "M_C_CPU0_SB_CB<3>")
	)
	(segment
		(start 282.811982 -233.016806)
		(end 281.89428 -233.016806)
		(width 0.20066)
		(layer "F.Cu")
		(net "M_C_CPU0_SB_CB<3>")
	)
	(segment
		(start 277.091394 -233.14279)
		(end 276.96541 -233.016806)
		(width 0.20066)
		(layer "F.Cu")
		(net "M_C_CPU0_SB_CB<3>")
	)
	(segment
		(start 280.606246 -233.29265)
		(end 280.457148 -233.441748)
		(width 0.20066)
		(layer "F.Cu")
		(net "M_C_CPU0_SB_CB<3>")
	)
	(segment
		(start 280.457148 -233.441748)
		(end 279.977342 -233.441748)
		(width 0.20066)
		(layer "F.Cu")
		(net "M_C_CPU0_SB_CB<3>")
	)
	(segment
		(start 277.456646 -233.441748)
		(end 277.233888 -233.441748)
		(width 0.20066)
		(layer "F.Cu")
		(net "M_C_CPU0_SB_CB<3>")
	)
	(segment
		(start 281.768296 -233.14279)
		(end 281.311096 -233.14279)
		(width 0.20066)
		(layer "F.Cu")
		(net "M_C_CPU0_SB_CB<3>")
	)
	(segment
		(start 283.916882 -233.016806)
		(end 282.811982 -233.016806)
		(width 0.20066)
		(layer "F.Cu")
		(net "M_C_CPU0_SB_CB<3>")
	)
	(segment
		(start 279.977342 -233.441748)
		(end 279.912826 -233.441748)
		(width 0.101854)
		(layer "F.Cu")
		(net "M_C_CPU0_SB_CB<3>")
	)
	(segment
		(start 281.89428 -233.016806)
		(end 281.768296 -233.14279)
		(width 0.20066)
		(layer "F.Cu")
		(net "M_C_CPU0_SB_CB<3>")
	)
	(segment
		(start 281.311096 -233.14279)
		(end 281.084528 -232.916222)
		(width 0.20066)
		(layer "F.Cu")
		(net "M_C_CPU0_SB_CB<3>")
	)
	(segment
		(start 277.091394 -233.299254)
		(end 277.091394 -233.14279)
		(width 0.20066)
		(layer "F.Cu")
		(net "M_C_CPU0_SB_CB<3>")
	)
	(segment
		(start 286.446214 -230.891588)
		(end 286.263334 -230.708708)
		(width 0.18288)
		(layer "In4.Cu")
		(net "M_C_CPU0_SB_CB<3>")
	)
	(segment
		(start 288.4932 -231.832658)
		(end 288.31032 -231.649778)
		(width 0.18288)
		(layer "In4.Cu")
		(net "M_C_CPU0_SB_CB<3>")
	)
	(segment
		(start 307.98008 -232.591864)
		(end 301.271178 -232.591864)
		(width 0.18288)
		(layer "In4.Cu")
		(net "M_C_CPU0_SB_CB<3>")
	)
	(segment
		(start 312.114692 -233.103928)
		(end 310.676544 -233.103928)
		(width 0.18288)
		(layer "In4.Cu")
		(net "M_C_CPU0_SB_CB<3>")
	)
	(segment
		(start 300.42104 -231.741726)
		(end 298.431204 -231.741726)
		(width 0.18288)
		(layer "In4.Cu")
		(net "M_C_CPU0_SB_CB<3>")
	)
	(segment
		(start 335.341468 -237.730792)
		(end 335.332578 -237.736126)
		(width 0.088646)
		(layer "In4.Cu")
		(net "M_C_CPU0_SB_CB<3>")
	)
	(segment
		(start 331.94244 -238.433102)
		(end 331.898752 -238.47679)
		(width 0.088646)
		(layer "In4.Cu")
		(net "M_C_CPU0_SB_CB<3>")
	)
	(segment
		(start 331.898752 -238.47679)
		(end 331.004164 -238.47679)
		(width 0.088646)
		(layer "In4.Cu")
		(net "M_C_CPU0_SB_CB<3>")
	)
	(segment
		(start 284.341824 -232.591864)
		(end 283.916882 -233.016806)
		(width 0.18288)
		(layer "In4.Cu")
		(net "M_C_CPU0_SB_CB<3>")
	)
	(segment
		(start 286.263334 -230.708708)
		(end 285.938214 -230.708708)
		(width 0.18288)
		(layer "In4.Cu")
		(net "M_C_CPU0_SB_CB<3>")
	)
	(segment
		(start 339.657182 -237.736126)
		(end 339.65134 -237.73257)
		(width 0.088646)
		(layer "In4.Cu")
		(net "M_C_CPU0_SB_CB<3>")
	)
	(segment
		(start 288.4932 -232.408984)
		(end 288.4932 -231.832658)
		(width 0.18288)
		(layer "In4.Cu")
		(net "M_C_CPU0_SB_CB<3>")
	)
	(segment
		(start 333.170784 -238.21009)
		(end 333.170784 -238.225584)
		(width 0.088646)
		(layer "In4.Cu")
		(net "M_C_CPU0_SB_CB<3>")
	)
	(segment
		(start 287.80232 -232.408984)
		(end 287.61944 -232.591864)
		(width 0.18288)
		(layer "In4.Cu")
		(net "M_C_CPU0_SB_CB<3>")
	)
	(segment
		(start 337.777582 -237.736126)
		(end 337.77174 -237.73257)
		(width 0.088646)
		(layer "In4.Cu")
		(net "M_C_CPU0_SB_CB<3>")
	)
	(segment
		(start 301.271178 -232.591864)
		(end 300.42104 -231.741726)
		(width 0.18288)
		(layer "In4.Cu")
		(net "M_C_CPU0_SB_CB<3>")
	)
	(segment
		(start 286.446214 -232.408984)
		(end 286.446214 -230.891588)
		(width 0.18288)
		(layer "In4.Cu")
		(net "M_C_CPU0_SB_CB<3>")
	)
	(segment
		(start 285.755334 -232.408984)
		(end 285.572454 -232.591864)
		(width 0.18288)
		(layer "In4.Cu")
		(net "M_C_CPU0_SB_CB<3>")
	)
	(segment
		(start 287.9852 -231.649778)
		(end 287.80232 -231.832658)
		(width 0.18288)
		(layer "In4.Cu")
		(net "M_C_CPU0_SB_CB<3>")
	)
	(segment
		(start 309.734458 -232.66527)
		(end 309.439056 -232.960672)
		(width 0.18288)
		(layer "In4.Cu")
		(net "M_C_CPU0_SB_CB<3>")
	)
	(segment
		(start 339.663024 -237.739428)
		(end 339.657182 -237.736126)
		(width 0.088646)
		(layer "In4.Cu")
		(net "M_C_CPU0_SB_CB<3>")
	)
	(segment
		(start 332.608936 -238.549942)
		(end 332.492096 -238.433102)
		(width 0.088646)
		(layer "In4.Cu")
		(net "M_C_CPU0_SB_CB<3>")
	)
	(segment
		(start 313.388248 -234.377484)
		(end 312.114692 -233.103928)
		(width 0.18288)
		(layer "In4.Cu")
		(net "M_C_CPU0_SB_CB<3>")
	)
	(segment
		(start 331.004164 -238.47679)
		(end 319.973706 -238.47679)
		(width 0.18288)
		(layer "In4.Cu")
		(net "M_C_CPU0_SB_CB<3>")
	)
	(segment
		(start 285.938214 -230.708708)
		(end 285.755334 -230.891588)
		(width 0.18288)
		(layer "In4.Cu")
		(net "M_C_CPU0_SB_CB<3>")
	)
	(segment
		(start 285.572454 -232.591864)
		(end 284.341824 -232.591864)
		(width 0.18288)
		(layer "In4.Cu")
		(net "M_C_CPU0_SB_CB<3>")
	)
	(segment
		(start 285.755334 -230.891588)
		(end 285.755334 -232.408984)
		(width 0.18288)
		(layer "In4.Cu")
		(net "M_C_CPU0_SB_CB<3>")
	)
	(segment
		(start 288.67608 -232.591864)
		(end 288.4932 -232.408984)
		(width 0.18288)
		(layer "In4.Cu")
		(net "M_C_CPU0_SB_CB<3>")
	)
	(segment
		(start 340.988904 -237.960408)
		(end 340.813644 -237.960408)
		(width 0.088646)
		(layer "In4.Cu")
		(net "M_C_CPU0_SB_CB<3>")
	)
	(segment
		(start 338.723224 -237.739428)
		(end 338.717382 -237.736126)
		(width 0.088646)
		(layer "In4.Cu")
		(net "M_C_CPU0_SB_CB<3>")
	)
	(segment
		(start 297.581066 -232.591864)
		(end 288.67608 -232.591864)
		(width 0.18288)
		(layer "In4.Cu")
		(net "M_C_CPU0_SB_CB<3>")
	)
	(segment
		(start 338.717382 -237.736126)
		(end 338.71154 -237.73257)
		(width 0.088646)
		(layer "In4.Cu")
		(net "M_C_CPU0_SB_CB<3>")
	)
	(segment
		(start 337.783424 -237.739428)
		(end 337.777582 -237.736126)
		(width 0.088646)
		(layer "In4.Cu")
		(net "M_C_CPU0_SB_CB<3>")
	)
	(segment
		(start 332.992222 -238.544862)
		(end 332.983332 -238.549942)
		(width 0.088646)
		(layer "In4.Cu")
		(net "M_C_CPU0_SB_CB<3>")
	)
	(segment
		(start 287.80232 -231.832658)
		(end 287.80232 -232.408984)
		(width 0.18288)
		(layer "In4.Cu")
		(net "M_C_CPU0_SB_CB<3>")
	)
	(segment
		(start 309.798212 -232.638854)
		(end 309.734458 -232.66527)
		(width 0.18288)
		(layer "In4.Cu")
		(net "M_C_CPU0_SB_CB<3>")
	)
	(segment
		(start 310.676544 -233.103928)
		(end 310.16448 -232.591864)
		(width 0.18288)
		(layer "In4.Cu")
		(net "M_C_CPU0_SB_CB<3>")
	)
	(segment
		(start 335.897982 -237.736126)
		(end 335.898236 -237.735872)
		(width 0.088646)
		(layer "In4.Cu")
		(net "M_C_CPU0_SB_CB<3>")
	)
	(segment
		(start 334.958182 -237.736126)
		(end 334.947768 -237.73003)
		(width 0.088646)
		(layer "In4.Cu")
		(net "M_C_CPU0_SB_CB<3>")
	)
	(segment
		(start 286.629094 -232.591864)
		(end 286.446214 -232.408984)
		(width 0.18288)
		(layer "In4.Cu")
		(net "M_C_CPU0_SB_CB<3>")
	)
	(segment
		(start 319.973706 -238.47679)
		(end 315.8744 -234.377484)
		(width 0.18288)
		(layer "In4.Cu")
		(net "M_C_CPU0_SB_CB<3>")
	)
	(segment
		(start 336.837782 -237.736126)
		(end 336.83321 -237.733332)
		(width 0.088646)
		(layer "In4.Cu")
		(net "M_C_CPU0_SB_CB<3>")
	)
	(segment
		(start 334.018636 -237.736126)
		(end 334.008222 -237.73003)
		(width 0.088646)
		(layer "In4.Cu")
		(net "M_C_CPU0_SB_CB<3>")
	)
	(segment
		(start 336.843624 -237.739428)
		(end 336.837782 -237.736126)
		(width 0.088646)
		(layer "In4.Cu")
		(net "M_C_CPU0_SB_CB<3>")
	)
	(segment
		(start 310.16448 -232.591864)
		(end 309.91175 -232.591864)
		(width 0.18288)
		(layer "In4.Cu")
		(net "M_C_CPU0_SB_CB<3>")
	)
	(segment
		(start 308.348888 -232.960672)
		(end 307.98008 -232.591864)
		(width 0.18288)
		(layer "In4.Cu")
		(net "M_C_CPU0_SB_CB<3>")
	)
	(segment
		(start 315.8744 -234.377484)
		(end 313.388248 -234.377484)
		(width 0.18288)
		(layer "In4.Cu")
		(net "M_C_CPU0_SB_CB<3>")
	)
	(segment
		(start 309.91175 -232.591864)
		(end 309.798212 -232.638854)
		(width 0.18288)
		(layer "In4.Cu")
		(net "M_C_CPU0_SB_CB<3>")
	)
	(segment
		(start 287.61944 -232.591864)
		(end 286.629094 -232.591864)
		(width 0.18288)
		(layer "In4.Cu")
		(net "M_C_CPU0_SB_CB<3>")
	)
	(segment
		(start 309.439056 -232.960672)
		(end 308.348888 -232.960672)
		(width 0.18288)
		(layer "In4.Cu")
		(net "M_C_CPU0_SB_CB<3>")
	)
	(segment
		(start 341.25408 -238.225584)
		(end 340.988904 -237.960408)
		(width 0.088646)
		(layer "In4.Cu")
		(net "M_C_CPU0_SB_CB<3>")
	)
	(segment
		(start 298.431204 -231.741726)
		(end 297.581066 -232.591864)
		(width 0.18288)
		(layer "In4.Cu")
		(net "M_C_CPU0_SB_CB<3>")
	)
	(segment
		(start 332.492096 -238.433102)
		(end 331.94244 -238.433102)
		(width 0.088646)
		(layer "In4.Cu")
		(net "M_C_CPU0_SB_CB<3>")
	)
	(segment
		(start 288.31032 -231.649778)
		(end 287.9852 -231.649778)
		(width 0.18288)
		(layer "In4.Cu")
		(net "M_C_CPU0_SB_CB<3>")
	)
	(arc
		(start 339.092032 -237.736126)
		(mid 338.908078 -237.786255)
		(end 338.723224 -237.739428)
		(width 0.088646)
		(layer "In4.Cu")
		(net "M_C_CPU0_SB_CB<3>")
	)
	(arc
		(start 336.83321 -237.733332)
		(mid 336.552546 -237.660324)
		(end 336.272632 -237.736126)
		(width 0.088646)
		(layer "In4.Cu")
		(net "M_C_CPU0_SB_CB<3>")
	)
	(arc
		(start 334.393032 -237.736126)
		(mid 334.205834 -237.786269)
		(end 334.018636 -237.736126)
		(width 0.088646)
		(layer "In4.Cu")
		(net "M_C_CPU0_SB_CB<3>")
	)
	(arc
		(start 334.947768 -237.73003)
		(mid 334.66959 -237.660307)
		(end 334.393032 -237.736126)
		(width 0.088646)
		(layer "In4.Cu")
		(net "M_C_CPU0_SB_CB<3>")
	)
	(arc
		(start 332.983332 -238.549942)
		(mid 332.796134 -238.600085)
		(end 332.608936 -238.549942)
		(width 0.088646)
		(layer "In4.Cu")
		(net "M_C_CPU0_SB_CB<3>")
	)
	(arc
		(start 338.152232 -237.736126)
		(mid 337.968278 -237.786255)
		(end 337.783424 -237.739428)
		(width 0.088646)
		(layer "In4.Cu")
		(net "M_C_CPU0_SB_CB<3>")
	)
	(arc
		(start 340.813644 -237.960408)
		(mid 340.470359 -237.682309)
		(end 340.031832 -237.736126)
		(width 0.088646)
		(layer "In4.Cu")
		(net "M_C_CPU0_SB_CB<3>")
	)
	(arc
		(start 338.71154 -237.73257)
		(mid 338.431405 -237.660287)
		(end 338.152232 -237.736126)
		(width 0.088646)
		(layer "In4.Cu")
		(net "M_C_CPU0_SB_CB<3>")
	)
	(arc
		(start 337.212432 -237.736126)
		(mid 337.028478 -237.786255)
		(end 336.843624 -237.739428)
		(width 0.088646)
		(layer "In4.Cu")
		(net "M_C_CPU0_SB_CB<3>")
	)
	(arc
		(start 339.65134 -237.73257)
		(mid 339.371205 -237.660287)
		(end 339.092032 -237.736126)
		(width 0.088646)
		(layer "In4.Cu")
		(net "M_C_CPU0_SB_CB<3>")
	)
	(arc
		(start 333.452978 -237.736126)
		(mid 333.250155 -237.936357)
		(end 333.170784 -238.21009)
		(width 0.088646)
		(layer "In4.Cu")
		(net "M_C_CPU0_SB_CB<3>")
	)
	(arc
		(start 334.008222 -237.73003)
		(mid 333.72979 -237.660184)
		(end 333.452978 -237.736126)
		(width 0.088646)
		(layer "In4.Cu")
		(net "M_C_CPU0_SB_CB<3>")
	)
	(arc
		(start 337.77174 -237.73257)
		(mid 337.491605 -237.660287)
		(end 337.212432 -237.736126)
		(width 0.088646)
		(layer "In4.Cu")
		(net "M_C_CPU0_SB_CB<3>")
	)
	(arc
		(start 340.031832 -237.736126)
		(mid 339.847878 -237.786255)
		(end 339.663024 -237.739428)
		(width 0.088646)
		(layer "In4.Cu")
		(net "M_C_CPU0_SB_CB<3>")
	)
	(arc
		(start 336.272632 -237.736126)
		(mid 336.085324 -237.786235)
		(end 335.897982 -237.736126)
		(width 0.088646)
		(layer "In4.Cu")
		(net "M_C_CPU0_SB_CB<3>")
	)
	(arc
		(start 333.170784 -238.225584)
		(mid 333.123105 -238.408484)
		(end 332.992222 -238.544862)
		(width 0.088646)
		(layer "In4.Cu")
		(net "M_C_CPU0_SB_CB<3>")
	)
	(arc
		(start 335.898236 -237.735872)
		(mid 335.62051 -237.660027)
		(end 335.341468 -237.730792)
		(width 0.088646)
		(layer "In4.Cu")
		(net "M_C_CPU0_SB_CB<3>")
	)
	(arc
		(start 335.332578 -237.736126)
		(mid 335.14538 -237.786269)
		(end 334.958182 -237.736126)
		(width 0.088646)
		(layer "In4.Cu")
		(net "M_C_CPU0_SB_CB<3>")
	)
	(segment
		(start 279.98547 -234.291632)
		(end 279.912826 -234.291632)
		(width 0.101854)
		(layer "F.Cu")
		(net "M_C_CPU0_SB_CB<2>")
	)
	(segment
		(start 280.545794 -234.291632)
		(end 279.98547 -234.291632)
		(width 0.20066)
		(layer "F.Cu")
		(net "M_C_CPU0_SB_CB<2>")
	)
	(segment
		(start 276.840188 -234.291632)
		(end 276.415246 -234.716574)
		(width 0.20066)
		(layer "F.Cu")
		(net "M_C_CPU0_SB_CB<2>")
	)
	(segment
		(start 281.497278 -234.716574)
		(end 281.285442 -234.92841)
		(width 0.20066)
		(layer "F.Cu")
		(net "M_C_CPU0_SB_CB<2>")
	)
	(segment
		(start 341.72398 -239.57534)
		(end 341.724234 -239.575086)
		(width 0.20066)
		(layer "F.Cu")
		(net "M_C_CPU0_SB_CB<2>")
	)
	(segment
		(start 283.916882 -234.716574)
		(end 282.811982 -234.716574)
		(width 0.20066)
		(layer "F.Cu")
		(net "M_C_CPU0_SB_CB<2>")
	)
	(segment
		(start 280.856944 -234.92841)
		(end 280.689558 -234.761024)
		(width 0.20066)
		(layer "F.Cu")
		(net "M_C_CPU0_SB_CB<2>")
	)
	(segment
		(start 280.689558 -234.435396)
		(end 280.545794 -234.291632)
		(width 0.20066)
		(layer "F.Cu")
		(net "M_C_CPU0_SB_CB<2>")
	)
	(segment
		(start 341.724234 -239.575086)
		(end 341.724234 -239.0394)
		(width 0.20066)
		(layer "F.Cu")
		(net "M_C_CPU0_SB_CB<2>")
	)
	(segment
		(start 277.852886 -234.291632)
		(end 277.448518 -234.291632)
		(width 0.101854)
		(layer "F.Cu")
		(net "M_C_CPU0_SB_CB<2>")
	)
	(segment
		(start 277.448518 -234.291632)
		(end 276.840188 -234.291632)
		(width 0.20066)
		(layer "F.Cu")
		(net "M_C_CPU0_SB_CB<2>")
	)
	(segment
		(start 282.811982 -234.716574)
		(end 281.497278 -234.716574)
		(width 0.20066)
		(layer "F.Cu")
		(net "M_C_CPU0_SB_CB<2>")
	)
	(segment
		(start 281.285442 -234.92841)
		(end 280.856944 -234.92841)
		(width 0.20066)
		(layer "F.Cu")
		(net "M_C_CPU0_SB_CB<2>")
	)
	(segment
		(start 276.415246 -234.716574)
		(end 275.268182 -234.716574)
		(width 0.20066)
		(layer "F.Cu")
		(net "M_C_CPU0_SB_CB<2>")
	)
	(segment
		(start 279.912826 -234.291632)
		(end 277.852886 -234.291632)
		(width 0.1016)
		(layer "F.Cu")
		(net "M_C_CPU0_SB_CB<2>")
	)
	(segment
		(start 280.689558 -234.761024)
		(end 280.689558 -234.435396)
		(width 0.20066)
		(layer "F.Cu")
		(net "M_C_CPU0_SB_CB<2>")
	)
	(segment
		(start 336.367882 -238.549942)
		(end 336.357468 -238.543846)
		(width 0.088646)
		(layer "In4.Cu")
		(net "M_C_CPU0_SB_CB<2>")
	)
	(segment
		(start 290.413948 -233.939588)
		(end 290.088828 -233.939588)
		(width 0.18288)
		(layer "In4.Cu")
		(net "M_C_CPU0_SB_CB<2>")
	)
	(segment
		(start 313.230768 -236.072172)
		(end 312.169048 -235.010452)
		(width 0.18288)
		(layer "In4.Cu")
		(net "M_C_CPU0_SB_CB<2>")
	)
	(segment
		(start 339.569298 -238.545624)
		(end 339.561932 -238.549942)
		(width 0.088646)
		(layer "In4.Cu")
		(net "M_C_CPU0_SB_CB<2>")
	)
	(segment
		(start 302.932592 -234.206796)
		(end 301.319438 -234.206796)
		(width 0.18288)
		(layer "In4.Cu")
		(net "M_C_CPU0_SB_CB<2>")
	)
	(segment
		(start 337.682332 -238.549942)
		(end 337.67776 -238.552736)
		(width 0.088646)
		(layer "In4.Cu")
		(net "M_C_CPU0_SB_CB<2>")
	)
	(segment
		(start 333.640684 -239.029494)
		(end 333.640684 -239.0394)
		(width 0.088646)
		(layer "In4.Cu")
		(net "M_C_CPU0_SB_CB<2>")
	)
	(segment
		(start 289.723068 -234.54868)
		(end 288.080196 -234.54868)
		(width 0.18288)
		(layer "In4.Cu")
		(net "M_C_CPU0_SB_CB<2>")
	)
	(segment
		(start 289.905948 -234.122468)
		(end 289.905948 -234.3658)
		(width 0.18288)
		(layer "In4.Cu")
		(net "M_C_CPU0_SB_CB<2>")
	)
	(segment
		(start 286.690054 -234.291124)
		(end 286.690054 -235.089446)
		(width 0.18288)
		(layer "In4.Cu")
		(net "M_C_CPU0_SB_CB<2>")
	)
	(segment
		(start 286.190436 -235.272326)
		(end 285.999174 -235.081064)
		(width 0.18288)
		(layer "In4.Cu")
		(net "M_C_CPU0_SB_CB<2>")
	)
	(segment
		(start 285.816294 -234.108244)
		(end 284.525212 -234.108244)
		(width 0.18288)
		(layer "In4.Cu")
		(net "M_C_CPU0_SB_CB<2>")
	)
	(segment
		(start 336.749898 -238.545624)
		(end 336.742532 -238.549942)
		(width 0.088646)
		(layer "In4.Cu")
		(net "M_C_CPU0_SB_CB<2>")
	)
	(segment
		(start 285.999174 -234.291124)
		(end 285.816294 -234.108244)
		(width 0.18288)
		(layer "In4.Cu")
		(net "M_C_CPU0_SB_CB<2>")
	)
	(segment
		(start 305.898804 -234.482132)
		(end 305.715924 -234.299252)
		(width 0.18288)
		(layer "In4.Cu")
		(net "M_C_CPU0_SB_CB<2>")
	)
	(segment
		(start 336.742532 -238.549942)
		(end 336.738722 -238.552228)
		(width 0.088646)
		(layer "In4.Cu")
		(net "M_C_CPU0_SB_CB<2>")
	)
	(segment
		(start 308.653434 -234.563158)
		(end 308.337966 -234.24769)
		(width 0.18288)
		(layer "In4.Cu")
		(net "M_C_CPU0_SB_CB<2>")
	)
	(segment
		(start 292.973506 -233.946192)
		(end 292.525196 -233.946192)
		(width 0.18288)
		(layer "In4.Cu")
		(net "M_C_CPU0_SB_CB<2>")
	)
	(segment
		(start 292.525196 -233.946192)
		(end 291.922708 -234.54868)
		(width 0.18288)
		(layer "In4.Cu")
		(net "M_C_CPU0_SB_CB<2>")
	)
	(segment
		(start 340.509098 -238.545624)
		(end 340.501732 -238.549942)
		(width 0.088646)
		(layer "In4.Cu")
		(net "M_C_CPU0_SB_CB<2>")
	)
	(segment
		(start 337.689698 -238.545624)
		(end 337.682332 -238.549942)
		(width 0.088646)
		(layer "In4.Cu")
		(net "M_C_CPU0_SB_CB<2>")
	)
	(segment
		(start 305.715924 -234.299252)
		(end 305.715924 -234.02925)
		(width 0.18288)
		(layer "In4.Cu")
		(net "M_C_CPU0_SB_CB<2>")
	)
	(segment
		(start 290.779708 -234.54868)
		(end 290.596828 -234.3658)
		(width 0.18288)
		(layer "In4.Cu")
		(net "M_C_CPU0_SB_CB<2>")
	)
	(segment
		(start 319.540636 -239.47247)
		(end 316.140338 -236.072172)
		(width 0.18288)
		(layer "In4.Cu")
		(net "M_C_CPU0_SB_CB<2>")
	)
	(segment
		(start 290.596828 -234.122468)
		(end 290.413948 -233.939588)
		(width 0.18288)
		(layer "In4.Cu")
		(net "M_C_CPU0_SB_CB<2>")
	)
	(segment
		(start 307.349906 -234.24769)
		(end 307.115464 -234.482132)
		(width 0.18288)
		(layer "In4.Cu")
		(net "M_C_CPU0_SB_CB<2>")
	)
	(segment
		(start 287.63976 -234.108244)
		(end 286.872934 -234.108244)
		(width 0.18288)
		(layer "In4.Cu")
		(net "M_C_CPU0_SB_CB<2>")
	)
	(segment
		(start 298.381674 -233.441748)
		(end 297.53179 -234.291632)
		(width 0.18288)
		(layer "In4.Cu")
		(net "M_C_CPU0_SB_CB<2>")
	)
	(segment
		(start 338.622132 -238.549942)
		(end 338.61756 -238.552736)
		(width 0.088646)
		(layer "In4.Cu")
		(net "M_C_CPU0_SB_CB<2>")
	)
	(segment
		(start 289.905948 -234.3658)
		(end 289.723068 -234.54868)
		(width 0.18288)
		(layer "In4.Cu")
		(net "M_C_CPU0_SB_CB<2>")
	)
	(segment
		(start 286.507174 -235.272326)
		(end 286.190436 -235.272326)
		(width 0.18288)
		(layer "In4.Cu")
		(net "M_C_CPU0_SB_CB<2>")
	)
	(segment
		(start 331.004164 -239.47247)
		(end 319.540636 -239.47247)
		(width 0.18288)
		(layer "In4.Cu")
		(net "M_C_CPU0_SB_CB<2>")
	)
	(segment
		(start 339.561932 -238.549942)
		(end 339.55736 -238.552736)
		(width 0.088646)
		(layer "In4.Cu")
		(net "M_C_CPU0_SB_CB<2>")
	)
	(segment
		(start 305.715924 -234.02925)
		(end 305.533044 -233.84637)
		(width 0.18288)
		(layer "In4.Cu")
		(net "M_C_CPU0_SB_CB<2>")
	)
	(segment
		(start 304.842164 -234.482132)
		(end 303.207928 -234.482132)
		(width 0.18288)
		(layer "In4.Cu")
		(net "M_C_CPU0_SB_CB<2>")
	)
	(segment
		(start 286.872934 -234.108244)
		(end 286.690054 -234.291124)
		(width 0.18288)
		(layer "In4.Cu")
		(net "M_C_CPU0_SB_CB<2>")
	)
	(segment
		(start 301.319438 -234.206796)
		(end 300.55439 -233.441748)
		(width 0.18288)
		(layer "In4.Cu")
		(net "M_C_CPU0_SB_CB<2>")
	)
	(segment
		(start 333.462122 -239.358678)
		(end 333.453232 -239.363758)
		(width 0.088646)
		(layer "In4.Cu")
		(net "M_C_CPU0_SB_CB<2>")
	)
	(segment
		(start 305.207924 -233.84637)
		(end 305.025044 -234.02925)
		(width 0.18288)
		(layer "In4.Cu")
		(net "M_C_CPU0_SB_CB<2>")
	)
	(segment
		(start 305.025044 -234.02925)
		(end 305.025044 -234.299252)
		(width 0.18288)
		(layer "In4.Cu")
		(net "M_C_CPU0_SB_CB<2>")
	)
	(segment
		(start 332.528164 -239.355122)
		(end 332.513432 -239.363758)
		(width 0.088646)
		(layer "In4.Cu")
		(net "M_C_CPU0_SB_CB<2>")
	)
	(segment
		(start 300.55439 -233.441748)
		(end 298.381674 -233.441748)
		(width 0.18288)
		(layer "In4.Cu")
		(net "M_C_CPU0_SB_CB<2>")
	)
	(segment
		(start 284.525212 -234.108244)
		(end 283.916882 -234.716574)
		(width 0.18288)
		(layer "In4.Cu")
		(net "M_C_CPU0_SB_CB<2>")
	)
	(segment
		(start 285.999174 -235.081064)
		(end 285.999174 -234.291124)
		(width 0.18288)
		(layer "In4.Cu")
		(net "M_C_CPU0_SB_CB<2>")
	)
	(segment
		(start 309.008526 -234.563158)
		(end 308.653434 -234.563158)
		(width 0.18288)
		(layer "In4.Cu")
		(net "M_C_CPU0_SB_CB<2>")
	)
	(segment
		(start 316.140338 -236.072172)
		(end 313.230768 -236.072172)
		(width 0.18288)
		(layer "In4.Cu")
		(net "M_C_CPU0_SB_CB<2>")
	)
	(segment
		(start 310.636666 -234.24769)
		(end 309.323994 -234.24769)
		(width 0.18288)
		(layer "In4.Cu")
		(net "M_C_CPU0_SB_CB<2>")
	)
	(segment
		(start 309.323994 -234.24769)
		(end 309.008526 -234.563158)
		(width 0.18288)
		(layer "In4.Cu")
		(net "M_C_CPU0_SB_CB<2>")
	)
	(segment
		(start 297.53179 -234.291632)
		(end 293.318946 -234.291632)
		(width 0.18288)
		(layer "In4.Cu")
		(net "M_C_CPU0_SB_CB<2>")
	)
	(segment
		(start 341.146892 -238.59617)
		(end 341.066882 -238.549942)
		(width 0.088646)
		(layer "In4.Cu")
		(net "M_C_CPU0_SB_CB<2>")
	)
	(segment
		(start 305.533044 -233.84637)
		(end 305.207924 -233.84637)
		(width 0.18288)
		(layer "In4.Cu")
		(net "M_C_CPU0_SB_CB<2>")
	)
	(segment
		(start 331.890624 -239.414304)
		(end 331.832458 -239.47247)
		(width 0.088646)
		(layer "In4.Cu")
		(net "M_C_CPU0_SB_CB<2>")
	)
	(segment
		(start 338.629498 -238.545624)
		(end 338.622132 -238.549942)
		(width 0.088646)
		(layer "In4.Cu")
		(net "M_C_CPU0_SB_CB<2>")
	)
	(segment
		(start 293.318946 -234.291632)
		(end 292.973506 -233.946192)
		(width 0.18288)
		(layer "In4.Cu")
		(net "M_C_CPU0_SB_CB<2>")
	)
	(segment
		(start 312.169048 -235.010452)
		(end 311.399428 -235.010452)
		(width 0.18288)
		(layer "In4.Cu")
		(net "M_C_CPU0_SB_CB<2>")
	)
	(segment
		(start 340.501732 -238.549942)
		(end 340.49716 -238.552736)
		(width 0.088646)
		(layer "In4.Cu")
		(net "M_C_CPU0_SB_CB<2>")
	)
	(segment
		(start 308.337966 -234.24769)
		(end 307.349906 -234.24769)
		(width 0.18288)
		(layer "In4.Cu")
		(net "M_C_CPU0_SB_CB<2>")
	)
	(segment
		(start 286.690054 -235.089446)
		(end 286.507174 -235.272326)
		(width 0.18288)
		(layer "In4.Cu")
		(net "M_C_CPU0_SB_CB<2>")
	)
	(segment
		(start 290.596828 -234.3658)
		(end 290.596828 -234.122468)
		(width 0.18288)
		(layer "In4.Cu")
		(net "M_C_CPU0_SB_CB<2>")
	)
	(segment
		(start 331.832458 -239.47247)
		(end 331.004164 -239.47247)
		(width 0.088646)
		(layer "In4.Cu")
		(net "M_C_CPU0_SB_CB<2>")
	)
	(segment
		(start 307.115464 -234.482132)
		(end 305.898804 -234.482132)
		(width 0.18288)
		(layer "In4.Cu")
		(net "M_C_CPU0_SB_CB<2>")
	)
	(segment
		(start 303.207928 -234.482132)
		(end 302.932592 -234.206796)
		(width 0.18288)
		(layer "In4.Cu")
		(net "M_C_CPU0_SB_CB<2>")
	)
	(segment
		(start 311.399428 -235.010452)
		(end 310.636666 -234.24769)
		(width 0.18288)
		(layer "In4.Cu")
		(net "M_C_CPU0_SB_CB<2>")
	)
	(segment
		(start 288.080196 -234.54868)
		(end 287.63976 -234.108244)
		(width 0.18288)
		(layer "In4.Cu")
		(net "M_C_CPU0_SB_CB<2>")
	)
	(segment
		(start 290.088828 -233.939588)
		(end 289.905948 -234.122468)
		(width 0.18288)
		(layer "In4.Cu")
		(net "M_C_CPU0_SB_CB<2>")
	)
	(segment
		(start 305.025044 -234.299252)
		(end 304.842164 -234.482132)
		(width 0.18288)
		(layer "In4.Cu")
		(net "M_C_CPU0_SB_CB<2>")
	)
	(segment
		(start 332.326234 -239.414304)
		(end 331.890624 -239.414304)
		(width 0.088646)
		(layer "In4.Cu")
		(net "M_C_CPU0_SB_CB<2>")
	)
	(segment
		(start 291.922708 -234.54868)
		(end 290.779708 -234.54868)
		(width 0.18288)
		(layer "In4.Cu")
		(net "M_C_CPU0_SB_CB<2>")
	)
	(arc
		(start 336.357468 -238.543846)
		(mid 336.07929 -238.474123)
		(end 335.802732 -238.549942)
		(width 0.088646)
		(layer "In4.Cu")
		(net "M_C_CPU0_SB_CB<2>")
	)
	(arc
		(start 341.724234 -239.0394)
		(mid 341.450062 -238.798899)
		(end 341.146892 -238.59617)
		(width 0.088646)
		(layer "In4.Cu")
		(net "M_C_CPU0_SB_CB<2>")
	)
	(arc
		(start 337.307682 -238.549942)
		(mid 337.029359 -238.474183)
		(end 336.749898 -238.545624)
		(width 0.088646)
		(layer "In4.Cu")
		(net "M_C_CPU0_SB_CB<2>")
	)
	(arc
		(start 339.187282 -238.549942)
		(mid 338.908959 -238.474183)
		(end 338.629498 -238.545624)
		(width 0.088646)
		(layer "In4.Cu")
		(net "M_C_CPU0_SB_CB<2>")
	)
	(arc
		(start 333.453232 -239.363758)
		(mid 333.266034 -239.413901)
		(end 333.078836 -239.363758)
		(width 0.088646)
		(layer "In4.Cu")
		(net "M_C_CPU0_SB_CB<2>")
	)
	(arc
		(start 332.513432 -239.363758)
		(mid 332.42316 -239.401357)
		(end 332.326234 -239.414304)
		(width 0.088646)
		(layer "In4.Cu")
		(net "M_C_CPU0_SB_CB<2>")
	)
	(arc
		(start 336.738722 -238.552228)
		(mid 336.553003 -238.60018)
		(end 336.367882 -238.549942)
		(width 0.088646)
		(layer "In4.Cu")
		(net "M_C_CPU0_SB_CB<2>")
	)
	(arc
		(start 334.488536 -238.549942)
		(mid 334.205834 -238.474166)
		(end 333.923132 -238.549942)
		(width 0.088646)
		(layer "In4.Cu")
		(net "M_C_CPU0_SB_CB<2>")
	)
	(arc
		(start 337.67776 -238.552736)
		(mid 337.492346 -238.600248)
		(end 337.307682 -238.549942)
		(width 0.088646)
		(layer "In4.Cu")
		(net "M_C_CPU0_SB_CB<2>")
	)
	(arc
		(start 339.55736 -238.552736)
		(mid 339.371946 -238.600248)
		(end 339.187282 -238.549942)
		(width 0.088646)
		(layer "In4.Cu")
		(net "M_C_CPU0_SB_CB<2>")
	)
	(arc
		(start 334.862932 -238.549942)
		(mid 334.675734 -238.600085)
		(end 334.488536 -238.549942)
		(width 0.088646)
		(layer "In4.Cu")
		(net "M_C_CPU0_SB_CB<2>")
	)
	(arc
		(start 333.640684 -239.0394)
		(mid 333.593005 -239.2223)
		(end 333.462122 -239.358678)
		(width 0.088646)
		(layer "In4.Cu")
		(net "M_C_CPU0_SB_CB<2>")
	)
	(arc
		(start 333.078836 -239.363758)
		(mid 332.804637 -239.287923)
		(end 332.528164 -239.355122)
		(width 0.088646)
		(layer "In4.Cu")
		(net "M_C_CPU0_SB_CB<2>")
	)
	(arc
		(start 333.923132 -238.549942)
		(mid 333.718797 -238.752547)
		(end 333.640684 -239.029494)
		(width 0.088646)
		(layer "In4.Cu")
		(net "M_C_CPU0_SB_CB<2>")
	)
	(arc
		(start 338.61756 -238.552736)
		(mid 338.432146 -238.600248)
		(end 338.247482 -238.549942)
		(width 0.088646)
		(layer "In4.Cu")
		(net "M_C_CPU0_SB_CB<2>")
	)
	(arc
		(start 335.428336 -238.549942)
		(mid 335.145634 -238.474166)
		(end 334.862932 -238.549942)
		(width 0.088646)
		(layer "In4.Cu")
		(net "M_C_CPU0_SB_CB<2>")
	)
	(arc
		(start 335.802732 -238.549942)
		(mid 335.615534 -238.600085)
		(end 335.428336 -238.549942)
		(width 0.088646)
		(layer "In4.Cu")
		(net "M_C_CPU0_SB_CB<2>")
	)
	(arc
		(start 338.247482 -238.549942)
		(mid 337.969159 -238.474183)
		(end 337.689698 -238.545624)
		(width 0.088646)
		(layer "In4.Cu")
		(net "M_C_CPU0_SB_CB<2>")
	)
	(arc
		(start 340.127082 -238.549942)
		(mid 339.848759 -238.474183)
		(end 339.569298 -238.545624)
		(width 0.088646)
		(layer "In4.Cu")
		(net "M_C_CPU0_SB_CB<2>")
	)
	(arc
		(start 341.066882 -238.549942)
		(mid 340.788559 -238.474183)
		(end 340.509098 -238.545624)
		(width 0.088646)
		(layer "In4.Cu")
		(net "M_C_CPU0_SB_CB<2>")
	)
	(arc
		(start 340.49716 -238.552736)
		(mid 340.311746 -238.600248)
		(end 340.127082 -238.549942)
		(width 0.088646)
		(layer "In4.Cu")
		(net "M_C_CPU0_SB_CB<2>")
	)
	(segment
		(start 278.711914 -233.86669)
		(end 277.072598 -233.86669)
		(width 0.20066)
		(layer "F.Cu")
		(net "M_C_CPU0_SB_CB<1>")
	)
	(segment
		(start 279.816814 -233.86669)
		(end 278.711914 -233.86669)
		(width 0.20066)
		(layer "F.Cu")
		(net "M_C_CPU0_SB_CB<1>")
	)
	(segment
		(start 272.713704 -234.078018)
		(end 272.502376 -233.86669)
		(width 0.20066)
		(layer "F.Cu")
		(net "M_C_CPU0_SB_CB<1>")
	)
	(segment
		(start 274.152868 -233.441748)
		(end 274.005802 -233.441748)
		(width 0.101854)
		(layer "F.Cu")
		(net "M_C_CPU0_SB_CB<1>")
	)
	(segment
		(start 277.072598 -233.86669)
		(end 276.647656 -233.441748)
		(width 0.20066)
		(layer "F.Cu")
		(net "M_C_CPU0_SB_CB<1>")
	)
	(segment
		(start 276.530562 -233.441748)
		(end 276.138386 -233.441748)
		(width 0.101854)
		(layer "F.Cu")
		(net "M_C_CPU0_SB_CB<1>")
	)
	(segment
		(start 273.37258 -233.604308)
		(end 273.37258 -233.923586)
		(width 0.20066)
		(layer "F.Cu")
		(net "M_C_CPU0_SB_CB<1>")
	)
	(segment
		(start 272.502376 -233.86669)
		(end 271.168114 -233.86669)
		(width 0.20066)
		(layer "F.Cu")
		(net "M_C_CPU0_SB_CB<1>")
	)
	(segment
		(start 340.314534 -238.761524)
		(end 340.31428 -238.76127)
		(width 0.20066)
		(layer "F.Cu")
		(net "M_C_CPU0_SB_CB<1>")
	)
	(segment
		(start 273.37258 -233.923586)
		(end 273.218148 -234.078018)
		(width 0.20066)
		(layer "F.Cu")
		(net "M_C_CPU0_SB_CB<1>")
	)
	(segment
		(start 340.31428 -238.76127)
		(end 340.31428 -238.225584)
		(width 0.20066)
		(layer "F.Cu")
		(net "M_C_CPU0_SB_CB<1>")
	)
	(segment
		(start 276.647656 -233.441748)
		(end 276.530562 -233.441748)
		(width 0.20066)
		(layer "F.Cu")
		(net "M_C_CPU0_SB_CB<1>")
	)
	(segment
		(start 273.218148 -234.078018)
		(end 272.713704 -234.078018)
		(width 0.20066)
		(layer "F.Cu")
		(net "M_C_CPU0_SB_CB<1>")
	)
	(segment
		(start 273.53514 -233.441748)
		(end 273.37258 -233.604308)
		(width 0.20066)
		(layer "F.Cu")
		(net "M_C_CPU0_SB_CB<1>")
	)
	(segment
		(start 274.005802 -233.441748)
		(end 273.53514 -233.441748)
		(width 0.20066)
		(layer "F.Cu")
		(net "M_C_CPU0_SB_CB<1>")
	)
	(segment
		(start 276.138386 -233.441748)
		(end 274.152868 -233.441748)
		(width 0.1016)
		(layer "F.Cu")
		(net "M_C_CPU0_SB_CB<1>")
	)
	(segment
		(start 307.363622 -233.70921)
		(end 307.002942 -233.34853)
		(width 0.18288)
		(layer "In4.Cu")
		(net "M_C_CPU0_SB_CB<1>")
	)
	(segment
		(start 331.004164 -238.97463)
		(end 319.765426 -238.97463)
		(width 0.18288)
		(layer "In4.Cu")
		(net "M_C_CPU0_SB_CB<1>")
	)
	(segment
		(start 315.764418 -234.973114)
		(end 314.83808 -234.973114)
		(width 0.18288)
		(layer "In4.Cu")
		(net "M_C_CPU0_SB_CB<1>")
	)
	(segment
		(start 281.52725 -232.858056)
		(end 281.52725 -233.258868)
		(width 0.18288)
		(layer "In4.Cu")
		(net "M_C_CPU0_SB_CB<1>")
	)
	(segment
		(start 337.682332 -237.900972)
		(end 337.67649 -237.89767)
		(width 0.088646)
		(layer "In4.Cu")
		(net "M_C_CPU0_SB_CB<1>")
	)
	(segment
		(start 319.765426 -238.97463)
		(end 315.764418 -234.973114)
		(width 0.18288)
		(layer "In4.Cu")
		(net "M_C_CPU0_SB_CB<1>")
	)
	(segment
		(start 338.622132 -237.900972)
		(end 338.61629 -237.89767)
		(width 0.088646)
		(layer "In4.Cu")
		(net "M_C_CPU0_SB_CB<1>")
	)
	(segment
		(start 314.837826 -234.973368)
		(end 312.921904 -234.973368)
		(width 0.18288)
		(layer "In4.Cu")
		(net "M_C_CPU0_SB_CB<1>")
	)
	(segment
		(start 280.241756 -233.441748)
		(end 279.816814 -233.86669)
		(width 0.18288)
		(layer "In4.Cu")
		(net "M_C_CPU0_SB_CB<1>")
	)
	(segment
		(start 303.93259 -233.554016)
		(end 301.441612 -233.554016)
		(width 0.18288)
		(layer "In4.Cu")
		(net "M_C_CPU0_SB_CB<1>")
	)
	(segment
		(start 337.688174 -237.904528)
		(end 337.682332 -237.900972)
		(width 0.088646)
		(layer "In4.Cu")
		(net "M_C_CPU0_SB_CB<1>")
	)
	(segment
		(start 340.31428 -238.225584)
		(end 340.627208 -238.225584)
		(width 0.088646)
		(layer "In4.Cu")
		(net "M_C_CPU0_SB_CB<1>")
	)
	(segment
		(start 335.802732 -237.900972)
		(end 335.802732 -237.901226)
		(width 0.088646)
		(layer "In4.Cu")
		(net "M_C_CPU0_SB_CB<1>")
	)
	(segment
		(start 281.34437 -233.441748)
		(end 280.241756 -233.441748)
		(width 0.18288)
		(layer "In4.Cu")
		(net "M_C_CPU0_SB_CB<1>")
	)
	(segment
		(start 333.548736 -237.901226)
		(end 333.539846 -237.906306)
		(width 0.088646)
		(layer "In4.Cu")
		(net "M_C_CPU0_SB_CB<1>")
	)
	(segment
		(start 282.40101 -233.441748)
		(end 282.21813 -233.258868)
		(width 0.18288)
		(layer "In4.Cu")
		(net "M_C_CPU0_SB_CB<1>")
	)
	(segment
		(start 301.441612 -233.554016)
		(end 300.47946 -232.591864)
		(width 0.18288)
		(layer "In4.Cu")
		(net "M_C_CPU0_SB_CB<1>")
	)
	(segment
		(start 311.703212 -234.433618)
		(end 310.978804 -233.70921)
		(width 0.18288)
		(layer "In4.Cu")
		(net "M_C_CPU0_SB_CB<1>")
	)
	(segment
		(start 336.742532 -237.900972)
		(end 336.738722 -237.89894)
		(width 0.088646)
		(layer "In4.Cu")
		(net "M_C_CPU0_SB_CB<1>")
	)
	(segment
		(start 334.877664 -237.909862)
		(end 334.862932 -237.901226)
		(width 0.088646)
		(layer "In4.Cu")
		(net "M_C_CPU0_SB_CB<1>")
	)
	(segment
		(start 307.002942 -233.34853)
		(end 304.138076 -233.34853)
		(width 0.18288)
		(layer "In4.Cu")
		(net "M_C_CPU0_SB_CB<1>")
	)
	(segment
		(start 332.061058 -238.774224)
		(end 332.061058 -238.774478)
		(width 0.088646)
		(layer "In4.Cu")
		(net "M_C_CPU0_SB_CB<1>")
	)
	(segment
		(start 282.21813 -233.258868)
		(end 282.21813 -232.858056)
		(width 0.18288)
		(layer "In4.Cu")
		(net "M_C_CPU0_SB_CB<1>")
	)
	(segment
		(start 332.061058 -238.774478)
		(end 331.860906 -238.97463)
		(width 0.088646)
		(layer "In4.Cu")
		(net "M_C_CPU0_SB_CB<1>")
	)
	(segment
		(start 314.83808 -234.973114)
		(end 314.837826 -234.973368)
		(width 0.18288)
		(layer "In4.Cu")
		(net "M_C_CPU0_SB_CB<1>")
	)
	(segment
		(start 282.21813 -232.858056)
		(end 282.03525 -232.675176)
		(width 0.18288)
		(layer "In4.Cu")
		(net "M_C_CPU0_SB_CB<1>")
	)
	(segment
		(start 304.138076 -233.34853)
		(end 303.93259 -233.554016)
		(width 0.18288)
		(layer "In4.Cu")
		(net "M_C_CPU0_SB_CB<1>")
	)
	(segment
		(start 298.498514 -232.591864)
		(end 297.64863 -233.441748)
		(width 0.18288)
		(layer "In4.Cu")
		(net "M_C_CPU0_SB_CB<1>")
	)
	(segment
		(start 340.506812 -237.90402)
		(end 340.501732 -237.900972)
		(width 0.088646)
		(layer "In4.Cu")
		(net "M_C_CPU0_SB_CB<1>")
	)
	(segment
		(start 339.561932 -237.900972)
		(end 339.55609 -237.89767)
		(width 0.088646)
		(layer "In4.Cu")
		(net "M_C_CPU0_SB_CB<1>")
	)
	(segment
		(start 312.382154 -234.433618)
		(end 311.703212 -234.433618)
		(width 0.18288)
		(layer "In4.Cu")
		(net "M_C_CPU0_SB_CB<1>")
	)
	(segment
		(start 336.748374 -237.904528)
		(end 336.742532 -237.900972)
		(width 0.088646)
		(layer "In4.Cu")
		(net "M_C_CPU0_SB_CB<1>")
	)
	(segment
		(start 338.627974 -237.904528)
		(end 338.622132 -237.900972)
		(width 0.088646)
		(layer "In4.Cu")
		(net "M_C_CPU0_SB_CB<1>")
	)
	(segment
		(start 281.52725 -233.258868)
		(end 281.34437 -233.441748)
		(width 0.18288)
		(layer "In4.Cu")
		(net "M_C_CPU0_SB_CB<1>")
	)
	(segment
		(start 339.567774 -237.904528)
		(end 339.561932 -237.900972)
		(width 0.088646)
		(layer "In4.Cu")
		(net "M_C_CPU0_SB_CB<1>")
	)
	(segment
		(start 281.71013 -232.675176)
		(end 281.52725 -232.858056)
		(width 0.18288)
		(layer "In4.Cu")
		(net "M_C_CPU0_SB_CB<1>")
	)
	(segment
		(start 340.501732 -237.900972)
		(end 340.49589 -237.89767)
		(width 0.088646)
		(layer "In4.Cu")
		(net "M_C_CPU0_SB_CB<1>")
	)
	(segment
		(start 340.627208 -238.225584)
		(end 340.684612 -238.16818)
		(width 0.088646)
		(layer "In4.Cu")
		(net "M_C_CPU0_SB_CB<1>")
	)
	(segment
		(start 282.03525 -232.675176)
		(end 281.71013 -232.675176)
		(width 0.18288)
		(layer "In4.Cu")
		(net "M_C_CPU0_SB_CB<1>")
	)
	(segment
		(start 300.47946 -232.591864)
		(end 298.498514 -232.591864)
		(width 0.18288)
		(layer "In4.Cu")
		(net "M_C_CPU0_SB_CB<1>")
	)
	(segment
		(start 312.921904 -234.973368)
		(end 312.382154 -234.433618)
		(width 0.18288)
		(layer "In4.Cu")
		(net "M_C_CPU0_SB_CB<1>")
	)
	(segment
		(start 297.64863 -233.441748)
		(end 282.40101 -233.441748)
		(width 0.18288)
		(layer "In4.Cu")
		(net "M_C_CPU0_SB_CB<1>")
	)
	(segment
		(start 310.978804 -233.70921)
		(end 307.363622 -233.70921)
		(width 0.18288)
		(layer "In4.Cu")
		(net "M_C_CPU0_SB_CB<1>")
	)
	(segment
		(start 333.361284 -238.225584)
		(end 333.361284 -238.23549)
		(width 0.088646)
		(layer "In4.Cu")
		(net "M_C_CPU0_SB_CB<1>")
	)
	(segment
		(start 331.860906 -238.97463)
		(end 331.004164 -238.97463)
		(width 0.088646)
		(layer "In4.Cu")
		(net "M_C_CPU0_SB_CB<1>")
	)
	(arc
		(start 333.923132 -237.901226)
		(mid 333.735934 -237.851083)
		(end 333.548736 -237.901226)
		(width 0.088646)
		(layer "In4.Cu")
		(net "M_C_CPU0_SB_CB<1>")
	)
	(arc
		(start 334.488536 -237.901226)
		(mid 334.205834 -237.977002)
		(end 333.923132 -237.901226)
		(width 0.088646)
		(layer "In4.Cu")
		(net "M_C_CPU0_SB_CB<1>")
	)
	(arc
		(start 335.428336 -237.901226)
		(mid 335.154137 -237.977061)
		(end 334.877664 -237.909862)
		(width 0.088646)
		(layer "In4.Cu")
		(net "M_C_CPU0_SB_CB<1>")
	)
	(arc
		(start 338.61629 -237.89767)
		(mid 338.431435 -237.850752)
		(end 338.247482 -237.900972)
		(width 0.088646)
		(layer "In4.Cu")
		(net "M_C_CPU0_SB_CB<1>")
	)
	(arc
		(start 337.67649 -237.89767)
		(mid 337.491635 -237.850752)
		(end 337.307682 -237.900972)
		(width 0.088646)
		(layer "In4.Cu")
		(net "M_C_CPU0_SB_CB<1>")
	)
	(arc
		(start 333.539846 -237.906306)
		(mid 333.408932 -238.042666)
		(end 333.361284 -238.225584)
		(width 0.088646)
		(layer "In4.Cu")
		(net "M_C_CPU0_SB_CB<1>")
	)
	(arc
		(start 336.738722 -237.89894)
		(mid 336.553032 -237.850862)
		(end 336.367882 -237.900972)
		(width 0.088646)
		(layer "In4.Cu")
		(net "M_C_CPU0_SB_CB<1>")
	)
	(arc
		(start 332.513432 -238.715042)
		(mid 332.326234 -238.664899)
		(end 332.139036 -238.715042)
		(width 0.088646)
		(layer "In4.Cu")
		(net "M_C_CPU0_SB_CB<1>")
	)
	(arc
		(start 332.139036 -238.715042)
		(mid 332.098106 -238.742075)
		(end 332.061058 -238.774224)
		(width 0.088646)
		(layer "In4.Cu")
		(net "M_C_CPU0_SB_CB<1>")
	)
	(arc
		(start 333.078836 -238.715042)
		(mid 332.796134 -238.790818)
		(end 332.513432 -238.715042)
		(width 0.088646)
		(layer "In4.Cu")
		(net "M_C_CPU0_SB_CB<1>")
	)
	(arc
		(start 339.55609 -237.89767)
		(mid 339.371235 -237.850752)
		(end 339.187282 -237.900972)
		(width 0.088646)
		(layer "In4.Cu")
		(net "M_C_CPU0_SB_CB<1>")
	)
	(arc
		(start 334.862932 -237.901226)
		(mid 334.675734 -237.851083)
		(end 334.488536 -237.901226)
		(width 0.088646)
		(layer "In4.Cu")
		(net "M_C_CPU0_SB_CB<1>")
	)
	(arc
		(start 340.127082 -237.900972)
		(mid 339.847908 -237.976771)
		(end 339.567774 -237.904528)
		(width 0.088646)
		(layer "In4.Cu")
		(net "M_C_CPU0_SB_CB<1>")
	)
	(arc
		(start 340.684612 -238.16818)
		(mid 340.625222 -238.016219)
		(end 340.506812 -237.90402)
		(width 0.088646)
		(layer "In4.Cu")
		(net "M_C_CPU0_SB_CB<1>")
	)
	(arc
		(start 339.187282 -237.900972)
		(mid 338.908108 -237.976771)
		(end 338.627974 -237.904528)
		(width 0.088646)
		(layer "In4.Cu")
		(net "M_C_CPU0_SB_CB<1>")
	)
	(arc
		(start 335.802732 -237.901226)
		(mid 335.615534 -237.851083)
		(end 335.428336 -237.901226)
		(width 0.088646)
		(layer "In4.Cu")
		(net "M_C_CPU0_SB_CB<1>")
	)
	(arc
		(start 337.307682 -237.900972)
		(mid 337.028508 -237.976771)
		(end 336.748374 -237.904528)
		(width 0.088646)
		(layer "In4.Cu")
		(net "M_C_CPU0_SB_CB<1>")
	)
	(arc
		(start 338.247482 -237.900972)
		(mid 337.968308 -237.976771)
		(end 337.688174 -237.904528)
		(width 0.088646)
		(layer "In4.Cu")
		(net "M_C_CPU0_SB_CB<1>")
	)
	(arc
		(start 333.361284 -238.23549)
		(mid 333.283173 -238.512439)
		(end 333.078836 -238.715042)
		(width 0.088646)
		(layer "In4.Cu")
		(net "M_C_CPU0_SB_CB<1>")
	)
	(arc
		(start 336.367882 -237.900972)
		(mid 336.085324 -237.976621)
		(end 335.802732 -237.900972)
		(width 0.088646)
		(layer "In4.Cu")
		(net "M_C_CPU0_SB_CB<1>")
	)
	(arc
		(start 340.49589 -237.89767)
		(mid 340.311035 -237.850752)
		(end 340.127082 -237.900972)
		(width 0.088646)
		(layer "In4.Cu")
		(net "M_C_CPU0_SB_CB<1>")
	)
	(segment
		(start 339.844634 -239.575086)
		(end 339.844634 -239.0394)
		(width 0.20066)
		(layer "F.Cu")
		(net "M_C_CPU0_SB_CB<0>")
	)
	(segment
		(start 273.37258 -235.343192)
		(end 273.37258 -235.632752)
		(width 0.20066)
		(layer "F.Cu")
		(net "M_C_CPU0_SB_CB<0>")
	)
	(segment
		(start 278.711914 -235.566712)
		(end 277.342854 -235.566712)
		(width 0.20066)
		(layer "F.Cu")
		(net "M_C_CPU0_SB_CB<0>")
	)
	(segment
		(start 276.469094 -235.14177)
		(end 274.40001 -235.14177)
		(width 0.1016)
		(layer "F.Cu")
		(net "M_C_CPU0_SB_CB<0>")
	)
	(segment
		(start 274.40001 -235.14177)
		(end 274.009866 -235.14177)
		(width 0.101854)
		(layer "F.Cu")
		(net "M_C_CPU0_SB_CB<0>")
	)
	(segment
		(start 274.009866 -235.14177)
		(end 273.574002 -235.14177)
		(width 0.20066)
		(layer "F.Cu")
		(net "M_C_CPU0_SB_CB<0>")
	)
	(segment
		(start 272.741136 -235.805472)
		(end 272.502376 -235.566712)
		(width 0.20066)
		(layer "F.Cu")
		(net "M_C_CPU0_SB_CB<0>")
	)
	(segment
		(start 273.37258 -235.632752)
		(end 273.19986 -235.805472)
		(width 0.20066)
		(layer "F.Cu")
		(net "M_C_CPU0_SB_CB<0>")
	)
	(segment
		(start 273.574002 -235.14177)
		(end 273.37258 -235.343192)
		(width 0.20066)
		(layer "F.Cu")
		(net "M_C_CPU0_SB_CB<0>")
	)
	(segment
		(start 339.84438 -239.57534)
		(end 339.844634 -239.575086)
		(width 0.20066)
		(layer "F.Cu")
		(net "M_C_CPU0_SB_CB<0>")
	)
	(segment
		(start 276.917912 -235.14177)
		(end 276.53869 -235.14177)
		(width 0.20066)
		(layer "F.Cu")
		(net "M_C_CPU0_SB_CB<0>")
	)
	(segment
		(start 279.816814 -235.566712)
		(end 278.711914 -235.566712)
		(width 0.20066)
		(layer "F.Cu")
		(net "M_C_CPU0_SB_CB<0>")
	)
	(segment
		(start 273.19986 -235.805472)
		(end 272.741136 -235.805472)
		(width 0.20066)
		(layer "F.Cu")
		(net "M_C_CPU0_SB_CB<0>")
	)
	(segment
		(start 276.53869 -235.14177)
		(end 276.469094 -235.14177)
		(width 0.101854)
		(layer "F.Cu")
		(net "M_C_CPU0_SB_CB<0>")
	)
	(segment
		(start 272.502376 -235.566712)
		(end 271.168114 -235.566712)
		(width 0.20066)
		(layer "F.Cu")
		(net "M_C_CPU0_SB_CB<0>")
	)
	(segment
		(start 277.342854 -235.566712)
		(end 276.917912 -235.14177)
		(width 0.20066)
		(layer "F.Cu")
		(net "M_C_CPU0_SB_CB<0>")
	)
	(segment
		(start 332.326234 -239.60455)
		(end 332.081378 -239.60455)
		(width 0.088646)
		(layer "In4.Cu")
		(net "M_C_CPU0_SB_CB<0>")
	)
	(segment
		(start 331.715618 -239.97031)
		(end 331.004164 -239.97031)
		(width 0.088646)
		(layer "In4.Cu")
		(net "M_C_CPU0_SB_CB<0>")
	)
	(segment
		(start 339.48878 -238.94415)
		(end 339.092032 -238.715042)
		(width 0.088646)
		(layer "In4.Cu")
		(net "M_C_CPU0_SB_CB<0>")
	)
	(segment
		(start 338.717382 -238.715042)
		(end 338.710016 -238.71936)
		(width 0.088646)
		(layer "In4.Cu")
		(net "M_C_CPU0_SB_CB<0>")
	)
	(segment
		(start 319.332356 -239.97031)
		(end 315.967618 -236.605572)
		(width 0.18288)
		(layer "In4.Cu")
		(net "M_C_CPU0_SB_CB<0>")
	)
	(segment
		(start 339.844634 -239.0394)
		(end 339.84438 -239.0394)
		(width 0.088646)
		(layer "In4.Cu")
		(net "M_C_CPU0_SB_CB<0>")
	)
	(segment
		(start 333.548482 -239.528858)
		(end 333.53375 -239.537494)
		(width 0.088646)
		(layer "In4.Cu")
		(net "M_C_CPU0_SB_CB<0>")
	)
	(segment
		(start 303.147476 -235.754672)
		(end 302.01489 -235.754672)
		(width 0.18288)
		(layer "In4.Cu")
		(net "M_C_CPU0_SB_CB<0>")
	)
	(segment
		(start 337.777582 -238.715042)
		(end 337.770216 -238.71936)
		(width 0.088646)
		(layer "In4.Cu")
		(net "M_C_CPU0_SB_CB<0>")
	)
	(segment
		(start 283.159962 -235.14177)
		(end 282.977082 -234.95889)
		(width 0.18288)
		(layer "In4.Cu")
		(net "M_C_CPU0_SB_CB<0>")
	)
	(segment
		(start 333.554578 -239.525302)
		(end 333.548482 -239.528858)
		(width 0.088646)
		(layer "In4.Cu")
		(net "M_C_CPU0_SB_CB<0>")
	)
	(segment
		(start 307.279294 -235.162852)
		(end 307.145436 -235.028994)
		(width 0.18288)
		(layer "In4.Cu")
		(net "M_C_CPU0_SB_CB<0>")
	)
	(segment
		(start 282.977082 -234.19435)
		(end 282.794202 -234.01147)
		(width 0.18288)
		(layer "In4.Cu")
		(net "M_C_CPU0_SB_CB<0>")
	)
	(segment
		(start 331.004164 -239.97031)
		(end 319.332356 -239.97031)
		(width 0.18288)
		(layer "In4.Cu")
		(net "M_C_CPU0_SB_CB<0>")
	)
	(segment
		(start 285.971996 -236.107986)
		(end 285.00578 -235.14177)
		(width 0.18288)
		(layer "In4.Cu")
		(net "M_C_CPU0_SB_CB<0>")
	)
	(segment
		(start 312.83148 -236.605572)
		(end 312.302906 -236.076998)
		(width 0.18288)
		(layer "In4.Cu")
		(net "M_C_CPU0_SB_CB<0>")
	)
	(segment
		(start 297.531536 -235.14177)
		(end 287.722564 -235.14177)
		(width 0.18288)
		(layer "In4.Cu")
		(net "M_C_CPU0_SB_CB<0>")
	)
	(segment
		(start 312.302906 -236.076998)
		(end 311.122314 -236.076998)
		(width 0.18288)
		(layer "In4.Cu")
		(net "M_C_CPU0_SB_CB<0>")
	)
	(segment
		(start 307.145436 -235.028994)
		(end 303.873154 -235.028994)
		(width 0.18288)
		(layer "In4.Cu")
		(net "M_C_CPU0_SB_CB<0>")
	)
	(segment
		(start 310.208168 -235.162852)
		(end 307.279294 -235.162852)
		(width 0.18288)
		(layer "In4.Cu")
		(net "M_C_CPU0_SB_CB<0>")
	)
	(segment
		(start 282.103322 -235.14177)
		(end 280.241756 -235.14177)
		(width 0.18288)
		(layer "In4.Cu")
		(net "M_C_CPU0_SB_CB<0>")
	)
	(segment
		(start 336.837782 -238.715042)
		(end 336.83321 -238.717582)
		(width 0.088646)
		(layer "In4.Cu")
		(net "M_C_CPU0_SB_CB<0>")
	)
	(segment
		(start 280.241756 -235.14177)
		(end 279.816814 -235.566712)
		(width 0.18288)
		(layer "In4.Cu")
		(net "M_C_CPU0_SB_CB<0>")
	)
	(segment
		(start 286.756348 -236.107986)
		(end 285.971996 -236.107986)
		(width 0.18288)
		(layer "In4.Cu")
		(net "M_C_CPU0_SB_CB<0>")
	)
	(segment
		(start 282.977082 -234.95889)
		(end 282.977082 -234.19435)
		(width 0.18288)
		(layer "In4.Cu")
		(net "M_C_CPU0_SB_CB<0>")
	)
	(segment
		(start 298.381674 -234.291632)
		(end 297.531536 -235.14177)
		(width 0.18288)
		(layer "In4.Cu")
		(net "M_C_CPU0_SB_CB<0>")
	)
	(segment
		(start 282.286202 -234.19435)
		(end 282.286202 -234.95889)
		(width 0.18288)
		(layer "In4.Cu")
		(net "M_C_CPU0_SB_CB<0>")
	)
	(segment
		(start 303.873154 -235.028994)
		(end 303.147476 -235.754672)
		(width 0.18288)
		(layer "In4.Cu")
		(net "M_C_CPU0_SB_CB<0>")
	)
	(segment
		(start 287.722564 -235.14177)
		(end 286.756348 -236.107986)
		(width 0.18288)
		(layer "In4.Cu")
		(net "M_C_CPU0_SB_CB<0>")
	)
	(segment
		(start 311.122314 -236.076998)
		(end 310.208168 -235.162852)
		(width 0.18288)
		(layer "In4.Cu")
		(net "M_C_CPU0_SB_CB<0>")
	)
	(segment
		(start 282.286202 -234.95889)
		(end 282.103322 -235.14177)
		(width 0.18288)
		(layer "In4.Cu")
		(net "M_C_CPU0_SB_CB<0>")
	)
	(segment
		(start 338.721954 -238.712248)
		(end 338.717382 -238.715042)
		(width 0.088646)
		(layer "In4.Cu")
		(net "M_C_CPU0_SB_CB<0>")
	)
	(segment
		(start 302.01489 -235.754672)
		(end 300.55185 -234.291632)
		(width 0.18288)
		(layer "In4.Cu")
		(net "M_C_CPU0_SB_CB<0>")
	)
	(segment
		(start 300.55185 -234.291632)
		(end 298.381674 -234.291632)
		(width 0.18288)
		(layer "In4.Cu")
		(net "M_C_CPU0_SB_CB<0>")
	)
	(segment
		(start 282.794202 -234.01147)
		(end 282.469082 -234.01147)
		(width 0.18288)
		(layer "In4.Cu")
		(net "M_C_CPU0_SB_CB<0>")
	)
	(segment
		(start 337.782154 -238.712248)
		(end 337.777582 -238.715042)
		(width 0.088646)
		(layer "In4.Cu")
		(net "M_C_CPU0_SB_CB<0>")
	)
	(segment
		(start 282.469082 -234.01147)
		(end 282.286202 -234.19435)
		(width 0.18288)
		(layer "In4.Cu")
		(net "M_C_CPU0_SB_CB<0>")
	)
	(segment
		(start 336.842354 -238.712248)
		(end 336.837782 -238.715042)
		(width 0.088646)
		(layer "In4.Cu")
		(net "M_C_CPU0_SB_CB<0>")
	)
	(segment
		(start 334.018636 -238.715042)
		(end 334.009746 -238.720122)
		(width 0.088646)
		(layer "In4.Cu")
		(net "M_C_CPU0_SB_CB<0>")
	)
	(segment
		(start 315.967618 -236.605572)
		(end 312.83148 -236.605572)
		(width 0.18288)
		(layer "In4.Cu")
		(net "M_C_CPU0_SB_CB<0>")
	)
	(segment
		(start 332.081378 -239.60455)
		(end 331.715618 -239.97031)
		(width 0.088646)
		(layer "In4.Cu")
		(net "M_C_CPU0_SB_CB<0>")
	)
	(segment
		(start 285.00578 -235.14177)
		(end 283.159962 -235.14177)
		(width 0.18288)
		(layer "In4.Cu")
		(net "M_C_CPU0_SB_CB<0>")
	)
	(arc
		(start 337.770216 -238.71936)
		(mid 337.490755 -238.790797)
		(end 337.212432 -238.715042)
		(width 0.088646)
		(layer "In4.Cu")
		(net "M_C_CPU0_SB_CB<0>")
	)
	(arc
		(start 334.958436 -238.715042)
		(mid 334.675734 -238.790818)
		(end 334.393032 -238.715042)
		(width 0.088646)
		(layer "In4.Cu")
		(net "M_C_CPU0_SB_CB<0>")
	)
	(arc
		(start 337.212432 -238.715042)
		(mid 337.027768 -238.664782)
		(end 336.842354 -238.712248)
		(width 0.088646)
		(layer "In4.Cu")
		(net "M_C_CPU0_SB_CB<0>")
	)
	(arc
		(start 335.332832 -238.715042)
		(mid 335.145634 -238.664899)
		(end 334.958436 -238.715042)
		(width 0.088646)
		(layer "In4.Cu")
		(net "M_C_CPU0_SB_CB<0>")
	)
	(arc
		(start 334.393032 -238.715042)
		(mid 334.205834 -238.664899)
		(end 334.018636 -238.715042)
		(width 0.088646)
		(layer "In4.Cu")
		(net "M_C_CPU0_SB_CB<0>")
	)
	(arc
		(start 332.983078 -239.528858)
		(mid 332.79588 -239.478715)
		(end 332.608682 -239.528858)
		(width 0.088646)
		(layer "In4.Cu")
		(net "M_C_CPU0_SB_CB<0>")
	)
	(arc
		(start 338.152232 -238.715042)
		(mid 337.967568 -238.664782)
		(end 337.782154 -238.712248)
		(width 0.088646)
		(layer "In4.Cu")
		(net "M_C_CPU0_SB_CB<0>")
	)
	(arc
		(start 338.710016 -238.71936)
		(mid 338.430555 -238.790797)
		(end 338.152232 -238.715042)
		(width 0.088646)
		(layer "In4.Cu")
		(net "M_C_CPU0_SB_CB<0>")
	)
	(arc
		(start 339.092032 -238.715042)
		(mid 338.907368 -238.664782)
		(end 338.721954 -238.712248)
		(width 0.088646)
		(layer "In4.Cu")
		(net "M_C_CPU0_SB_CB<0>")
	)
	(arc
		(start 335.898236 -238.715042)
		(mid 335.615534 -238.790818)
		(end 335.332832 -238.715042)
		(width 0.088646)
		(layer "In4.Cu")
		(net "M_C_CPU0_SB_CB<0>")
	)
	(arc
		(start 333.53375 -239.537494)
		(mid 333.257275 -239.604814)
		(end 332.983078 -239.528858)
		(width 0.088646)
		(layer "In4.Cu")
		(net "M_C_CPU0_SB_CB<0>")
	)
	(arc
		(start 333.831184 -239.0394)
		(mid 333.757193 -239.318966)
		(end 333.554578 -239.525302)
		(width 0.088646)
		(layer "In4.Cu")
		(net "M_C_CPU0_SB_CB<0>")
	)
	(arc
		(start 332.608682 -239.528858)
		(mid 332.47244 -239.585292)
		(end 332.326234 -239.60455)
		(width 0.088646)
		(layer "In4.Cu")
		(net "M_C_CPU0_SB_CB<0>")
	)
	(arc
		(start 336.272632 -238.715042)
		(mid 336.085434 -238.664899)
		(end 335.898236 -238.715042)
		(width 0.088646)
		(layer "In4.Cu")
		(net "M_C_CPU0_SB_CB<0>")
	)
	(arc
		(start 339.84438 -239.0394)
		(mid 339.660295 -239.015222)
		(end 339.48878 -238.94415)
		(width 0.088646)
		(layer "In4.Cu")
		(net "M_C_CPU0_SB_CB<0>")
	)
	(arc
		(start 334.009746 -238.720122)
		(mid 333.878832 -238.856482)
		(end 333.831184 -239.0394)
		(width 0.088646)
		(layer "In4.Cu")
		(net "M_C_CPU0_SB_CB<0>")
	)
	(arc
		(start 336.83321 -238.717582)
		(mid 336.552575 -238.79075)
		(end 336.272632 -238.715042)
		(width 0.088646)
		(layer "In4.Cu")
		(net "M_C_CPU0_SB_CB<0>")
	)
	(segment
		(start 279.816814 -247.466612)
		(end 278.711914 -247.466612)
		(width 0.20066)
		(layer "F.Cu")
		(net "M_C_CPU0_SB_CA<6>")
	)
	(segment
		(start 273.218148 -247.67794)
		(end 272.713704 -247.67794)
		(width 0.20066)
		(layer "F.Cu")
		(net "M_C_CPU0_SB_CA<6>")
	)
	(segment
		(start 276.469094 -247.04167)
		(end 276.138386 -247.04167)
		(width 0.101854)
		(layer "F.Cu")
		(net "M_C_CPU0_SB_CA<6>")
	)
	(segment
		(start 272.713704 -247.67794)
		(end 272.502376 -247.466612)
		(width 0.20066)
		(layer "F.Cu")
		(net "M_C_CPU0_SB_CA<6>")
	)
	(segment
		(start 273.37258 -247.19534)
		(end 273.37258 -247.523508)
		(width 0.20066)
		(layer "F.Cu")
		(net "M_C_CPU0_SB_CA<6>")
	)
	(segment
		(start 272.502376 -247.466612)
		(end 271.168114 -247.466612)
		(width 0.20066)
		(layer "F.Cu")
		(net "M_C_CPU0_SB_CA<6>")
	)
	(segment
		(start 274.143978 -247.03278)
		(end 273.53514 -247.03278)
		(width 0.20066)
		(layer "F.Cu")
		(net "M_C_CPU0_SB_CA<6>")
	)
	(segment
		(start 273.37258 -247.523508)
		(end 273.218148 -247.67794)
		(width 0.20066)
		(layer "F.Cu")
		(net "M_C_CPU0_SB_CA<6>")
	)
	(segment
		(start 277.072598 -247.466612)
		(end 276.647656 -247.04167)
		(width 0.20066)
		(layer "F.Cu")
		(net "M_C_CPU0_SB_CA<6>")
	)
	(segment
		(start 276.647656 -247.04167)
		(end 276.469094 -247.04167)
		(width 0.20066)
		(layer "F.Cu")
		(net "M_C_CPU0_SB_CA<6>")
	)
	(segment
		(start 339.37448 -245.272306)
		(end 339.37448 -244.73662)
		(width 0.20066)
		(layer "F.Cu")
		(net "M_C_CPU0_SB_CA<6>")
	)
	(segment
		(start 276.138386 -247.04167)
		(end 274.152868 -247.04167)
		(width 0.1016)
		(layer "F.Cu")
		(net "M_C_CPU0_SB_CA<6>")
	)
	(segment
		(start 278.711914 -247.466612)
		(end 277.072598 -247.466612)
		(width 0.20066)
		(layer "F.Cu")
		(net "M_C_CPU0_SB_CA<6>")
	)
	(segment
		(start 339.374734 -245.27256)
		(end 339.37448 -245.272306)
		(width 0.20066)
		(layer "F.Cu")
		(net "M_C_CPU0_SB_CA<6>")
	)
	(segment
		(start 273.53514 -247.03278)
		(end 273.37258 -247.19534)
		(width 0.20066)
		(layer "F.Cu")
		(net "M_C_CPU0_SB_CA<6>")
	)
	(segment
		(start 274.152868 -247.04167)
		(end 274.143978 -247.03278)
		(width 0.1016)
		(layer "F.Cu")
		(net "M_C_CPU0_SB_CA<6>")
	)
	(segment
		(start 331.670914 -247.01119)
		(end 331.004418 -247.01119)
		(width 0.088646)
		(layer "In4.Cu")
		(net "M_C_CPU0_SB_CA<6>")
	)
	(segment
		(start 284.08884 -247.891808)
		(end 280.24201 -247.891808)
		(width 0.18288)
		(layer "In4.Cu")
		(net "M_C_CPU0_SB_CA<6>")
	)
	(segment
		(start 289.645598 -248.243852)
		(end 289.293554 -247.891808)
		(width 0.18288)
		(layer "In4.Cu")
		(net "M_C_CPU0_SB_CA<6>")
	)
	(segment
		(start 315.480446 -247.01119)
		(end 314.299092 -248.192544)
		(width 0.18288)
		(layer "In4.Cu")
		(net "M_C_CPU0_SB_CA<6>")
	)
	(segment
		(start 312.89752 -247.718326)
		(end 312.89752 -247.731788)
		(width 0.18288)
		(layer "In4.Cu")
		(net "M_C_CPU0_SB_CA<6>")
	)
	(segment
		(start 289.986974 -248.243852)
		(end 289.645598 -248.243852)
		(width 0.18288)
		(layer "In4.Cu")
		(net "M_C_CPU0_SB_CA<6>")
	)
	(segment
		(start 331.752448 -246.929656)
		(end 331.670914 -247.01119)
		(width 0.088646)
		(layer "In4.Cu")
		(net "M_C_CPU0_SB_CA<6>")
	)
	(segment
		(start 338.717382 -245.226332)
		(end 338.706968 -245.232428)
		(width 0.088646)
		(layer "In4.Cu")
		(net "M_C_CPU0_SB_CA<6>")
	)
	(segment
		(start 314.299092 -248.192544)
		(end 313.72556 -248.192544)
		(width 0.18288)
		(layer "In4.Cu")
		(net "M_C_CPU0_SB_CA<6>")
	)
	(segment
		(start 288.600134 -248.243852)
		(end 288.258758 -248.243852)
		(width 0.18288)
		(layer "In4.Cu")
		(net "M_C_CPU0_SB_CA<6>")
	)
	(segment
		(start 335.347564 -245.234968)
		(end 335.332832 -245.226332)
		(width 0.088646)
		(layer "In4.Cu")
		(net "M_C_CPU0_SB_CA<6>")
	)
	(segment
		(start 289.293554 -247.891808)
		(end 288.952178 -247.891808)
		(width 0.18288)
		(layer "In4.Cu")
		(net "M_C_CPU0_SB_CA<6>")
	)
	(segment
		(start 334.488536 -246.040148)
		(end 334.479646 -246.045228)
		(width 0.088646)
		(layer "In4.Cu")
		(net "M_C_CPU0_SB_CA<6>")
	)
	(segment
		(start 313.72556 -248.192544)
		(end 313.56554 -248.032524)
		(width 0.18288)
		(layer "In4.Cu")
		(net "M_C_CPU0_SB_CA<6>")
	)
	(segment
		(start 286.512 -247.891808)
		(end 286.351472 -247.73128)
		(width 0.18288)
		(layer "In4.Cu")
		(net "M_C_CPU0_SB_CA<6>")
	)
	(segment
		(start 336.8294 -245.231158)
		(end 336.827368 -245.232428)
		(width 0.088646)
		(layer "In4.Cu")
		(net "M_C_CPU0_SB_CA<6>")
	)
	(segment
		(start 339.37448 -244.73662)
		(end 338.746846 -245.209314)
		(width 0.088646)
		(layer "In4.Cu")
		(net "M_C_CPU0_SB_CA<6>")
	)
	(segment
		(start 334.770984 -245.55069)
		(end 334.770984 -245.560596)
		(width 0.088646)
		(layer "In4.Cu")
		(net "M_C_CPU0_SB_CA<6>")
	)
	(segment
		(start 338.732876 -245.217188)
		(end 338.717382 -245.226332)
		(width 0.088646)
		(layer "In4.Cu")
		(net "M_C_CPU0_SB_CA<6>")
	)
	(segment
		(start 313.40552 -247.558306)
		(end 313.05754 -247.558306)
		(width 0.18288)
		(layer "In4.Cu")
		(net "M_C_CPU0_SB_CA<6>")
	)
	(segment
		(start 338.746846 -245.209314)
		(end 338.732876 -245.217188)
		(width 0.088646)
		(layer "In4.Cu")
		(net "M_C_CPU0_SB_CA<6>")
	)
	(segment
		(start 337.227164 -245.234968)
		(end 337.212432 -245.226332)
		(width 0.088646)
		(layer "In4.Cu")
		(net "M_C_CPU0_SB_CA<6>")
	)
	(segment
		(start 280.24201 -247.891808)
		(end 279.816814 -247.466612)
		(width 0.18288)
		(layer "In4.Cu")
		(net "M_C_CPU0_SB_CA<6>")
	)
	(segment
		(start 312.89752 -247.731788)
		(end 312.7375 -247.891808)
		(width 0.18288)
		(layer "In4.Cu")
		(net "M_C_CPU0_SB_CA<6>")
	)
	(segment
		(start 284.249368 -247.73128)
		(end 284.08884 -247.891808)
		(width 0.18288)
		(layer "In4.Cu")
		(net "M_C_CPU0_SB_CA<6>")
	)
	(segment
		(start 290.339018 -247.891808)
		(end 289.986974 -248.243852)
		(width 0.18288)
		(layer "In4.Cu")
		(net "M_C_CPU0_SB_CA<6>")
	)
	(segment
		(start 288.952178 -247.891808)
		(end 288.600134 -248.243852)
		(width 0.18288)
		(layer "In4.Cu")
		(net "M_C_CPU0_SB_CA<6>")
	)
	(segment
		(start 331.004418 -247.01119)
		(end 315.480446 -247.01119)
		(width 0.18288)
		(layer "In4.Cu")
		(net "M_C_CPU0_SB_CA<6>")
	)
	(segment
		(start 336.838036 -245.226332)
		(end 336.8294 -245.231158)
		(width 0.088646)
		(layer "In4.Cu")
		(net "M_C_CPU0_SB_CA<6>")
	)
	(segment
		(start 312.7375 -247.891808)
		(end 290.339018 -247.891808)
		(width 0.18288)
		(layer "In4.Cu")
		(net "M_C_CPU0_SB_CA<6>")
	)
	(segment
		(start 286.351472 -247.73128)
		(end 284.249368 -247.73128)
		(width 0.18288)
		(layer "In4.Cu")
		(net "M_C_CPU0_SB_CA<6>")
	)
	(segment
		(start 334.301084 -246.364506)
		(end 334.301084 -246.374412)
		(width 0.088646)
		(layer "In4.Cu")
		(net "M_C_CPU0_SB_CA<6>")
	)
	(segment
		(start 334.958436 -245.226332)
		(end 334.949546 -245.231412)
		(width 0.088646)
		(layer "In4.Cu")
		(net "M_C_CPU0_SB_CA<6>")
	)
	(segment
		(start 313.05754 -247.558306)
		(end 312.89752 -247.718326)
		(width 0.18288)
		(layer "In4.Cu")
		(net "M_C_CPU0_SB_CA<6>")
	)
	(segment
		(start 287.906714 -247.891808)
		(end 286.512 -247.891808)
		(width 0.18288)
		(layer "In4.Cu")
		(net "M_C_CPU0_SB_CA<6>")
	)
	(segment
		(start 313.56554 -247.718326)
		(end 313.40552 -247.558306)
		(width 0.18288)
		(layer "In4.Cu")
		(net "M_C_CPU0_SB_CA<6>")
	)
	(segment
		(start 313.56554 -248.032524)
		(end 313.56554 -247.718326)
		(width 0.18288)
		(layer "In4.Cu")
		(net "M_C_CPU0_SB_CA<6>")
	)
	(segment
		(start 331.856334 -246.929656)
		(end 331.752448 -246.929656)
		(width 0.088646)
		(layer "In4.Cu")
		(net "M_C_CPU0_SB_CA<6>")
	)
	(segment
		(start 288.258758 -248.243852)
		(end 287.906714 -247.891808)
		(width 0.18288)
		(layer "In4.Cu")
		(net "M_C_CPU0_SB_CA<6>")
	)
	(arc
		(start 335.898236 -245.226332)
		(mid 335.624007 -245.302257)
		(end 335.347564 -245.234968)
		(width 0.088646)
		(layer "In4.Cu")
		(net "M_C_CPU0_SB_CA<6>")
	)
	(arc
		(start 334.770984 -245.560596)
		(mid 334.692873 -245.837545)
		(end 334.488536 -246.040148)
		(width 0.088646)
		(layer "In4.Cu")
		(net "M_C_CPU0_SB_CA<6>")
	)
	(arc
		(start 338.152232 -245.226332)
		(mid 337.965034 -245.176189)
		(end 337.777836 -245.226332)
		(width 0.088646)
		(layer "In4.Cu")
		(net "M_C_CPU0_SB_CA<6>")
	)
	(arc
		(start 332.139036 -246.853964)
		(mid 332.002667 -246.910406)
		(end 331.856334 -246.929656)
		(width 0.088646)
		(layer "In4.Cu")
		(net "M_C_CPU0_SB_CA<6>")
	)
	(arc
		(start 337.212432 -245.226332)
		(mid 337.025234 -245.176189)
		(end 336.838036 -245.226332)
		(width 0.088646)
		(layer "In4.Cu")
		(net "M_C_CPU0_SB_CA<6>")
	)
	(arc
		(start 333.078836 -246.853964)
		(mid 332.796134 -246.92974)
		(end 332.513432 -246.853964)
		(width 0.088646)
		(layer "In4.Cu")
		(net "M_C_CPU0_SB_CA<6>")
	)
	(arc
		(start 335.332832 -245.226332)
		(mid 335.145634 -245.176189)
		(end 334.958436 -245.226332)
		(width 0.088646)
		(layer "In4.Cu")
		(net "M_C_CPU0_SB_CA<6>")
	)
	(arc
		(start 334.018636 -246.853964)
		(mid 333.735934 -246.92974)
		(end 333.453232 -246.853964)
		(width 0.088646)
		(layer "In4.Cu")
		(net "M_C_CPU0_SB_CA<6>")
	)
	(arc
		(start 333.453232 -246.853964)
		(mid 333.266034 -246.803821)
		(end 333.078836 -246.853964)
		(width 0.088646)
		(layer "In4.Cu")
		(net "M_C_CPU0_SB_CA<6>")
	)
	(arc
		(start 334.479646 -246.045228)
		(mid 334.348732 -246.181588)
		(end 334.301084 -246.364506)
		(width 0.088646)
		(layer "In4.Cu")
		(net "M_C_CPU0_SB_CA<6>")
	)
	(arc
		(start 332.513432 -246.853964)
		(mid 332.326234 -246.803821)
		(end 332.139036 -246.853964)
		(width 0.088646)
		(layer "In4.Cu")
		(net "M_C_CPU0_SB_CA<6>")
	)
	(arc
		(start 337.777836 -245.226332)
		(mid 337.503607 -245.302257)
		(end 337.227164 -245.234968)
		(width 0.088646)
		(layer "In4.Cu")
		(net "M_C_CPU0_SB_CA<6>")
	)
	(arc
		(start 334.301084 -246.374412)
		(mid 334.222973 -246.651361)
		(end 334.018636 -246.853964)
		(width 0.088646)
		(layer "In4.Cu")
		(net "M_C_CPU0_SB_CA<6>")
	)
	(arc
		(start 338.706968 -245.232428)
		(mid 338.42879 -245.30212)
		(end 338.152232 -245.226332)
		(width 0.088646)
		(layer "In4.Cu")
		(net "M_C_CPU0_SB_CA<6>")
	)
	(arc
		(start 334.949546 -245.231412)
		(mid 334.818632 -245.367772)
		(end 334.770984 -245.55069)
		(width 0.088646)
		(layer "In4.Cu")
		(net "M_C_CPU0_SB_CA<6>")
	)
	(arc
		(start 336.272632 -245.226332)
		(mid 336.085434 -245.176189)
		(end 335.898236 -245.226332)
		(width 0.088646)
		(layer "In4.Cu")
		(net "M_C_CPU0_SB_CA<6>")
	)
	(arc
		(start 336.827368 -245.232428)
		(mid 336.54919 -245.30212)
		(end 336.272632 -245.226332)
		(width 0.088646)
		(layer "In4.Cu")
		(net "M_C_CPU0_SB_CA<6>")
	)
	(segment
		(start 280.606246 -248.440956)
		(end 280.606246 -248.592594)
		(width 0.20066)
		(layer "F.Cu")
		(net "M_C_CPU0_SB_CA<5>")
	)
	(segment
		(start 283.916882 -248.31675)
		(end 282.811982 -248.31675)
		(width 0.20066)
		(layer "F.Cu")
		(net "M_C_CPU0_SB_CA<5>")
	)
	(segment
		(start 280.606246 -248.592594)
		(end 280.457148 -248.741692)
		(width 0.20066)
		(layer "F.Cu")
		(net "M_C_CPU0_SB_CA<5>")
	)
	(segment
		(start 280.457148 -248.741692)
		(end 279.912826 -248.741692)
		(width 0.20066)
		(layer "F.Cu")
		(net "M_C_CPU0_SB_CA<5>")
	)
	(segment
		(start 281.129994 -248.312432)
		(end 280.73477 -248.312432)
		(width 0.20066)
		(layer "F.Cu")
		(net "M_C_CPU0_SB_CA<5>")
	)
	(segment
		(start 279.912826 -248.741692)
		(end 277.839932 -248.741692)
		(width 0.1016)
		(layer "F.Cu")
		(net "M_C_CPU0_SB_CA<5>")
	)
	(segment
		(start 280.73477 -248.312432)
		(end 280.606246 -248.440956)
		(width 0.20066)
		(layer "F.Cu")
		(net "M_C_CPU0_SB_CA<5>")
	)
	(segment
		(start 341.724234 -246.086376)
		(end 341.724234 -245.55069)
		(width 0.20066)
		(layer "F.Cu")
		(net "M_C_CPU0_SB_CA<5>")
	)
	(segment
		(start 341.72398 -246.08663)
		(end 341.724234 -246.086376)
		(width 0.20066)
		(layer "F.Cu")
		(net "M_C_CPU0_SB_CA<5>")
	)
	(segment
		(start 282.811982 -248.31675)
		(end 281.99588 -248.31675)
		(width 0.20066)
		(layer "F.Cu")
		(net "M_C_CPU0_SB_CA<5>")
	)
	(segment
		(start 281.34183 -248.524268)
		(end 281.129994 -248.312432)
		(width 0.20066)
		(layer "F.Cu")
		(net "M_C_CPU0_SB_CA<5>")
	)
	(segment
		(start 277.839932 -248.741692)
		(end 277.601934 -248.741692)
		(width 0.101854)
		(layer "F.Cu")
		(net "M_C_CPU0_SB_CA<5>")
	)
	(segment
		(start 281.99588 -248.31675)
		(end 281.788362 -248.524268)
		(width 0.20066)
		(layer "F.Cu")
		(net "M_C_CPU0_SB_CA<5>")
	)
	(segment
		(start 276.96541 -248.31675)
		(end 275.268182 -248.31675)
		(width 0.20066)
		(layer "F.Cu")
		(net "M_C_CPU0_SB_CA<5>")
	)
	(segment
		(start 277.091394 -248.613422)
		(end 277.091394 -248.442734)
		(width 0.20066)
		(layer "F.Cu")
		(net "M_C_CPU0_SB_CA<5>")
	)
	(segment
		(start 277.601934 -248.741692)
		(end 277.58771 -248.755916)
		(width 0.101854)
		(layer "F.Cu")
		(net "M_C_CPU0_SB_CA<5>")
	)
	(segment
		(start 281.788362 -248.524268)
		(end 281.34183 -248.524268)
		(width 0.20066)
		(layer "F.Cu")
		(net "M_C_CPU0_SB_CA<5>")
	)
	(segment
		(start 277.58771 -248.755916)
		(end 277.233888 -248.755916)
		(width 0.20066)
		(layer "F.Cu")
		(net "M_C_CPU0_SB_CA<5>")
	)
	(segment
		(start 277.233888 -248.755916)
		(end 277.091394 -248.613422)
		(width 0.20066)
		(layer "F.Cu")
		(net "M_C_CPU0_SB_CA<5>")
	)
	(segment
		(start 277.091394 -248.442734)
		(end 276.96541 -248.31675)
		(width 0.20066)
		(layer "F.Cu")
		(net "M_C_CPU0_SB_CA<5>")
	)
	(segment
		(start 332.35646 -247.63222)
		(end 331.825092 -247.63222)
		(width 0.088646)
		(layer "In4.Cu")
		(net "M_C_CPU0_SB_CA<5>")
	)
	(segment
		(start 334.401922 -247.4976)
		(end 334.393032 -247.50268)
		(width 0.088646)
		(layer "In4.Cu")
		(net "M_C_CPU0_SB_CA<5>")
	)
	(segment
		(start 335.050384 -246.3546)
		(end 335.050384 -246.364506)
		(width 0.088646)
		(layer "In4.Cu")
		(net "M_C_CPU0_SB_CA<5>")
	)
	(segment
		(start 336.287364 -245.866412)
		(end 336.272632 -245.875048)
		(width 0.088646)
		(layer "In4.Cu")
		(net "M_C_CPU0_SB_CA<5>")
	)
	(segment
		(start 301.052484 -248.741692)
		(end 300.659292 -248.741692)
		(width 0.18288)
		(layer "In4.Cu")
		(net "M_C_CPU0_SB_CA<5>")
	)
	(segment
		(start 302.041052 -248.741692)
		(end 301.743364 -249.03938)
		(width 0.18288)
		(layer "In4.Cu")
		(net "M_C_CPU0_SB_CA<5>")
	)
	(segment
		(start 339.27923 -245.536466)
		(end 339.27923 -245.55069)
		(width 0.088646)
		(layer "In4.Cu")
		(net "M_C_CPU0_SB_CA<5>")
	)
	(segment
		(start 299.968412 -249.03938)
		(end 299.670724 -248.741692)
		(width 0.18288)
		(layer "In4.Cu")
		(net "M_C_CPU0_SB_CA<5>")
	)
	(segment
		(start 312.352944 -248.708926)
		(end 310.75757 -248.708926)
		(width 0.18288)
		(layer "In4.Cu")
		(net "M_C_CPU0_SB_CA<5>")
	)
	(segment
		(start 303.422812 -248.741692)
		(end 303.125124 -249.03938)
		(width 0.18288)
		(layer "In4.Cu")
		(net "M_C_CPU0_SB_CA<5>")
	)
	(segment
		(start 299.670724 -248.741692)
		(end 284.898084 -248.741692)
		(width 0.18288)
		(layer "In4.Cu")
		(net "M_C_CPU0_SB_CA<5>")
	)
	(segment
		(start 305.796442 -248.741692)
		(end 303.422812 -248.741692)
		(width 0.18288)
		(layer "In4.Cu")
		(net "M_C_CPU0_SB_CA<5>")
	)
	(segment
		(start 302.731932 -249.03938)
		(end 302.434244 -248.741692)
		(width 0.18288)
		(layer "In4.Cu")
		(net "M_C_CPU0_SB_CA<5>")
	)
	(segment
		(start 337.227164 -245.866412)
		(end 337.212432 -245.875048)
		(width 0.088646)
		(layer "In4.Cu")
		(net "M_C_CPU0_SB_CA<5>")
	)
	(segment
		(start 334.580484 -247.168416)
		(end 334.580484 -247.178322)
		(width 0.088646)
		(layer "In4.Cu")
		(net "M_C_CPU0_SB_CA<5>")
	)
	(segment
		(start 301.350172 -249.03938)
		(end 301.052484 -248.741692)
		(width 0.18288)
		(layer "In4.Cu")
		(net "M_C_CPU0_SB_CA<5>")
	)
	(segment
		(start 332.396338 -247.592342)
		(end 332.35646 -247.63222)
		(width 0.088646)
		(layer "In4.Cu")
		(net "M_C_CPU0_SB_CA<5>")
	)
	(segment
		(start 309.71871 -248.835418)
		(end 309.490364 -248.607072)
		(width 0.18288)
		(layer "In4.Cu")
		(net "M_C_CPU0_SB_CA<5>")
	)
	(segment
		(start 305.931062 -248.607072)
		(end 305.796442 -248.741692)
		(width 0.18288)
		(layer "In4.Cu")
		(net "M_C_CPU0_SB_CA<5>")
	)
	(segment
		(start 313.043824 -249.199908)
		(end 312.718704 -249.199908)
		(width 0.18288)
		(layer "In4.Cu")
		(net "M_C_CPU0_SB_CA<5>")
	)
	(segment
		(start 312.535824 -248.891806)
		(end 312.352944 -248.708926)
		(width 0.18288)
		(layer "In4.Cu")
		(net "M_C_CPU0_SB_CA<5>")
	)
	(segment
		(start 340.671912 -245.114826)
		(end 340.325964 -245.114826)
		(width 0.088646)
		(layer "In4.Cu")
		(net "M_C_CPU0_SB_CA<5>")
	)
	(segment
		(start 301.743364 -249.03938)
		(end 301.350172 -249.03938)
		(width 0.18288)
		(layer "In4.Cu")
		(net "M_C_CPU0_SB_CA<5>")
	)
	(segment
		(start 313.226704 -249.017028)
		(end 313.043824 -249.199908)
		(width 0.18288)
		(layer "In4.Cu")
		(net "M_C_CPU0_SB_CA<5>")
	)
	(segment
		(start 307.266848 -248.607072)
		(end 305.931062 -248.607072)
		(width 0.18288)
		(layer "In4.Cu")
		(net "M_C_CPU0_SB_CA<5>")
	)
	(segment
		(start 331.825092 -247.63222)
		(end 331.701902 -247.50903)
		(width 0.088646)
		(layer "In4.Cu")
		(net "M_C_CPU0_SB_CA<5>")
	)
	(segment
		(start 309.490364 -248.607072)
		(end 308.331108 -248.607072)
		(width 0.18288)
		(layer "In4.Cu")
		(net "M_C_CPU0_SB_CA<5>")
	)
	(segment
		(start 284.473142 -248.31675)
		(end 283.916882 -248.31675)
		(width 0.18288)
		(layer "In4.Cu")
		(net "M_C_CPU0_SB_CA<5>")
	)
	(segment
		(start 331.701902 -247.50903)
		(end 331.004418 -247.50903)
		(width 0.088646)
		(layer "In4.Cu")
		(net "M_C_CPU0_SB_CA<5>")
	)
	(segment
		(start 313.226704 -248.891806)
		(end 313.226704 -249.017028)
		(width 0.18288)
		(layer "In4.Cu")
		(net "M_C_CPU0_SB_CA<5>")
	)
	(segment
		(start 302.434244 -248.741692)
		(end 302.041052 -248.741692)
		(width 0.18288)
		(layer "In4.Cu")
		(net "M_C_CPU0_SB_CA<5>")
	)
	(segment
		(start 340.127336 -245.060978)
		(end 340.116922 -245.054882)
		(width 0.088646)
		(layer "In4.Cu")
		(net "M_C_CPU0_SB_CA<5>")
	)
	(segment
		(start 313.409584 -248.708926)
		(end 313.226704 -248.891806)
		(width 0.18288)
		(layer "In4.Cu")
		(net "M_C_CPU0_SB_CA<5>")
	)
	(segment
		(start 303.125124 -249.03938)
		(end 302.731932 -249.03938)
		(width 0.18288)
		(layer "In4.Cu")
		(net "M_C_CPU0_SB_CA<5>")
	)
	(segment
		(start 339.100668 -245.869968)
		(end 339.091778 -245.875048)
		(width 0.088646)
		(layer "In4.Cu")
		(net "M_C_CPU0_SB_CA<5>")
	)
	(segment
		(start 310.75757 -248.708926)
		(end 310.631078 -248.835418)
		(width 0.18288)
		(layer "In4.Cu")
		(net "M_C_CPU0_SB_CA<5>")
	)
	(segment
		(start 307.579268 -248.919492)
		(end 307.266848 -248.607072)
		(width 0.18288)
		(layer "In4.Cu")
		(net "M_C_CPU0_SB_CA<5>")
	)
	(segment
		(start 308.331108 -248.607072)
		(end 308.018688 -248.919492)
		(width 0.18288)
		(layer "In4.Cu")
		(net "M_C_CPU0_SB_CA<5>")
	)
	(segment
		(start 308.018688 -248.919492)
		(end 307.579268 -248.919492)
		(width 0.18288)
		(layer "In4.Cu")
		(net "M_C_CPU0_SB_CA<5>")
	)
	(segment
		(start 338.162646 -245.868952)
		(end 338.152232 -245.875048)
		(width 0.088646)
		(layer "In4.Cu")
		(net "M_C_CPU0_SB_CA<5>")
	)
	(segment
		(start 310.631078 -248.835418)
		(end 309.71871 -248.835418)
		(width 0.18288)
		(layer "In4.Cu")
		(net "M_C_CPU0_SB_CA<5>")
	)
	(segment
		(start 300.361604 -249.03938)
		(end 299.968412 -249.03938)
		(width 0.18288)
		(layer "In4.Cu")
		(net "M_C_CPU0_SB_CA<5>")
	)
	(segment
		(start 312.535824 -249.017028)
		(end 312.535824 -248.891806)
		(width 0.18288)
		(layer "In4.Cu")
		(net "M_C_CPU0_SB_CA<5>")
	)
	(segment
		(start 322.695062 -247.50903)
		(end 321.055238 -249.148854)
		(width 0.18288)
		(layer "In4.Cu")
		(net "M_C_CPU0_SB_CA<5>")
	)
	(segment
		(start 284.898084 -248.741692)
		(end 284.473142 -248.31675)
		(width 0.18288)
		(layer "In4.Cu")
		(net "M_C_CPU0_SB_CA<5>")
	)
	(segment
		(start 312.718704 -249.199908)
		(end 312.535824 -249.017028)
		(width 0.18288)
		(layer "In4.Cu")
		(net "M_C_CPU0_SB_CA<5>")
	)
	(segment
		(start 314.354718 -248.708926)
		(end 313.409584 -248.708926)
		(width 0.18288)
		(layer "In4.Cu")
		(net "M_C_CPU0_SB_CA<5>")
	)
	(segment
		(start 321.055238 -249.148854)
		(end 314.794646 -249.148854)
		(width 0.18288)
		(layer "In4.Cu")
		(net "M_C_CPU0_SB_CA<5>")
	)
	(segment
		(start 300.659292 -248.741692)
		(end 300.361604 -249.03938)
		(width 0.18288)
		(layer "In4.Cu")
		(net "M_C_CPU0_SB_CA<5>")
	)
	(segment
		(start 314.794646 -249.148854)
		(end 314.354718 -248.708926)
		(width 0.18288)
		(layer "In4.Cu")
		(net "M_C_CPU0_SB_CA<5>")
	)
	(segment
		(start 334.871822 -246.683784)
		(end 334.862932 -246.688864)
		(width 0.088646)
		(layer "In4.Cu")
		(net "M_C_CPU0_SB_CA<5>")
	)
	(segment
		(start 331.004418 -247.50903)
		(end 322.695062 -247.50903)
		(width 0.18288)
		(layer "In4.Cu")
		(net "M_C_CPU0_SB_CA<5>")
	)
	(arc
		(start 337.777836 -245.875048)
		(mid 337.503637 -245.799213)
		(end 337.227164 -245.866412)
		(width 0.088646)
		(layer "In4.Cu")
		(net "M_C_CPU0_SB_CA<5>")
	)
	(arc
		(start 341.724234 -245.55069)
		(mid 341.241425 -245.228087)
		(end 340.671912 -245.114826)
		(width 0.088646)
		(layer "In4.Cu")
		(net "M_C_CPU0_SB_CA<5>")
	)
	(arc
		(start 339.561678 -245.060978)
		(mid 339.358373 -245.261844)
		(end 339.27923 -245.536466)
		(width 0.088646)
		(layer "In4.Cu")
		(net "M_C_CPU0_SB_CA<5>")
	)
	(arc
		(start 336.272632 -245.875048)
		(mid 336.085434 -245.925191)
		(end 335.898236 -245.875048)
		(width 0.088646)
		(layer "In4.Cu")
		(net "M_C_CPU0_SB_CA<5>")
	)
	(arc
		(start 332.513432 -247.50268)
		(mid 332.451954 -247.543682)
		(end 332.396338 -247.592342)
		(width 0.088646)
		(layer "In4.Cu")
		(net "M_C_CPU0_SB_CA<5>")
	)
	(arc
		(start 340.116922 -245.054882)
		(mid 339.83849 -244.985068)
		(end 339.561678 -245.060978)
		(width 0.088646)
		(layer "In4.Cu")
		(net "M_C_CPU0_SB_CA<5>")
	)
	(arc
		(start 340.325964 -245.114826)
		(mid 340.223066 -245.101123)
		(end 340.127336 -245.060978)
		(width 0.088646)
		(layer "In4.Cu")
		(net "M_C_CPU0_SB_CA<5>")
	)
	(arc
		(start 337.212432 -245.875048)
		(mid 337.025234 -245.925191)
		(end 336.838036 -245.875048)
		(width 0.088646)
		(layer "In4.Cu")
		(net "M_C_CPU0_SB_CA<5>")
	)
	(arc
		(start 336.838036 -245.875048)
		(mid 336.563837 -245.799213)
		(end 336.287364 -245.866412)
		(width 0.088646)
		(layer "In4.Cu")
		(net "M_C_CPU0_SB_CA<5>")
	)
	(arc
		(start 333.453232 -247.50268)
		(mid 333.266034 -247.552823)
		(end 333.078836 -247.50268)
		(width 0.088646)
		(layer "In4.Cu")
		(net "M_C_CPU0_SB_CA<5>")
	)
	(arc
		(start 339.27923 -245.55069)
		(mid 339.231551 -245.73359)
		(end 339.100668 -245.869968)
		(width 0.088646)
		(layer "In4.Cu")
		(net "M_C_CPU0_SB_CA<5>")
	)
	(arc
		(start 335.332832 -245.875048)
		(mid 335.128497 -246.077653)
		(end 335.050384 -246.3546)
		(width 0.088646)
		(layer "In4.Cu")
		(net "M_C_CPU0_SB_CA<5>")
	)
	(arc
		(start 333.078836 -247.50268)
		(mid 332.796134 -247.426904)
		(end 332.513432 -247.50268)
		(width 0.088646)
		(layer "In4.Cu")
		(net "M_C_CPU0_SB_CA<5>")
	)
	(arc
		(start 334.393032 -247.50268)
		(mid 334.205834 -247.552823)
		(end 334.018636 -247.50268)
		(width 0.088646)
		(layer "In4.Cu")
		(net "M_C_CPU0_SB_CA<5>")
	)
	(arc
		(start 334.862932 -246.688864)
		(mid 334.658597 -246.891469)
		(end 334.580484 -247.168416)
		(width 0.088646)
		(layer "In4.Cu")
		(net "M_C_CPU0_SB_CA<5>")
	)
	(arc
		(start 338.717382 -245.875048)
		(mid 338.440823 -245.799305)
		(end 338.162646 -245.868952)
		(width 0.088646)
		(layer "In4.Cu")
		(net "M_C_CPU0_SB_CA<5>")
	)
	(arc
		(start 334.018636 -247.50268)
		(mid 333.735934 -247.426904)
		(end 333.453232 -247.50268)
		(width 0.088646)
		(layer "In4.Cu")
		(net "M_C_CPU0_SB_CA<5>")
	)
	(arc
		(start 335.898236 -245.875048)
		(mid 335.615534 -245.799272)
		(end 335.332832 -245.875048)
		(width 0.088646)
		(layer "In4.Cu")
		(net "M_C_CPU0_SB_CA<5>")
	)
	(arc
		(start 338.152232 -245.875048)
		(mid 337.965034 -245.925191)
		(end 337.777836 -245.875048)
		(width 0.088646)
		(layer "In4.Cu")
		(net "M_C_CPU0_SB_CA<5>")
	)
	(arc
		(start 339.091778 -245.875048)
		(mid 338.90458 -245.925191)
		(end 338.717382 -245.875048)
		(width 0.088646)
		(layer "In4.Cu")
		(net "M_C_CPU0_SB_CA<5>")
	)
	(arc
		(start 334.580484 -247.178322)
		(mid 334.532805 -247.361222)
		(end 334.401922 -247.4976)
		(width 0.088646)
		(layer "In4.Cu")
		(net "M_C_CPU0_SB_CA<5>")
	)
	(arc
		(start 335.050384 -246.364506)
		(mid 335.002705 -246.547406)
		(end 334.871822 -246.683784)
		(width 0.088646)
		(layer "In4.Cu")
		(net "M_C_CPU0_SB_CA<5>")
	)
	(segment
		(start 276.469094 -248.741692)
		(end 276.138386 -248.741692)
		(width 0.101854)
		(layer "F.Cu")
		(net "M_C_CPU0_SB_CA<4>")
	)
	(segment
		(start 272.502376 -249.166634)
		(end 271.168114 -249.166634)
		(width 0.20066)
		(layer "F.Cu")
		(net "M_C_CPU0_SB_CA<4>")
	)
	(segment
		(start 277.072598 -249.166634)
		(end 276.647656 -248.741692)
		(width 0.20066)
		(layer "F.Cu")
		(net "M_C_CPU0_SB_CA<4>")
	)
	(segment
		(start 274.143978 -248.732802)
		(end 273.53514 -248.732802)
		(width 0.20066)
		(layer "F.Cu")
		(net "M_C_CPU0_SB_CA<4>")
	)
	(segment
		(start 276.138386 -248.741692)
		(end 274.152868 -248.741692)
		(width 0.1016)
		(layer "F.Cu")
		(net "M_C_CPU0_SB_CA<4>")
	)
	(segment
		(start 273.37258 -248.895362)
		(end 273.37258 -249.22353)
		(width 0.20066)
		(layer "F.Cu")
		(net "M_C_CPU0_SB_CA<4>")
	)
	(segment
		(start 276.647656 -248.741692)
		(end 276.469094 -248.741692)
		(width 0.20066)
		(layer "F.Cu")
		(net "M_C_CPU0_SB_CA<4>")
	)
	(segment
		(start 279.816814 -249.166634)
		(end 278.711914 -249.166634)
		(width 0.20066)
		(layer "F.Cu")
		(net "M_C_CPU0_SB_CA<4>")
	)
	(segment
		(start 278.711914 -249.166634)
		(end 277.072598 -249.166634)
		(width 0.20066)
		(layer "F.Cu")
		(net "M_C_CPU0_SB_CA<4>")
	)
	(segment
		(start 339.844634 -246.086376)
		(end 339.844634 -245.55069)
		(width 0.20066)
		(layer "F.Cu")
		(net "M_C_CPU0_SB_CA<4>")
	)
	(segment
		(start 272.713704 -249.377962)
		(end 272.502376 -249.166634)
		(width 0.20066)
		(layer "F.Cu")
		(net "M_C_CPU0_SB_CA<4>")
	)
	(segment
		(start 273.37258 -249.22353)
		(end 273.218148 -249.377962)
		(width 0.20066)
		(layer "F.Cu")
		(net "M_C_CPU0_SB_CA<4>")
	)
	(segment
		(start 273.218148 -249.377962)
		(end 272.713704 -249.377962)
		(width 0.20066)
		(layer "F.Cu")
		(net "M_C_CPU0_SB_CA<4>")
	)
	(segment
		(start 339.84438 -246.08663)
		(end 339.844634 -246.086376)
		(width 0.20066)
		(layer "F.Cu")
		(net "M_C_CPU0_SB_CA<4>")
	)
	(segment
		(start 274.152868 -248.741692)
		(end 274.143978 -248.732802)
		(width 0.1016)
		(layer "F.Cu")
		(net "M_C_CPU0_SB_CA<4>")
	)
	(segment
		(start 273.53514 -248.732802)
		(end 273.37258 -248.895362)
		(width 0.20066)
		(layer "F.Cu")
		(net "M_C_CPU0_SB_CA<4>")
	)
	(segment
		(start 311.77103 -249.732292)
		(end 311.471564 -249.432826)
		(width 0.18288)
		(layer "In4.Cu")
		(net "M_C_CPU0_SB_CA<4>")
	)
	(segment
		(start 332.530958 -247.726962)
		(end 332.068424 -248.189496)
		(width 0.088646)
		(layer "In4.Cu")
		(net "M_C_CPU0_SB_CA<4>")
	)
	(segment
		(start 334.958436 -246.853964)
		(end 334.949546 -246.859044)
		(width 0.088646)
		(layer "In4.Cu")
		(net "M_C_CPU0_SB_CA<4>")
	)
	(segment
		(start 293.17061 -249.59183)
		(end 293.168832 -249.590052)
		(width 0.18288)
		(layer "In4.Cu")
		(net "M_C_CPU0_SB_CA<4>")
	)
	(segment
		(start 329.845416 -247.84431)
		(end 323.153786 -247.84431)
		(width 0.18288)
		(layer "In4.Cu")
		(net "M_C_CPU0_SB_CA<4>")
	)
	(segment
		(start 323.153786 -247.84431)
		(end 321.266058 -249.732038)
		(width 0.18288)
		(layer "In4.Cu")
		(net "M_C_CPU0_SB_CA<4>")
	)
	(segment
		(start 313.866276 -249.732038)
		(end 313.866022 -249.732292)
		(width 0.18288)
		(layer "In4.Cu")
		(net "M_C_CPU0_SB_CA<4>")
	)
	(segment
		(start 280.241756 -248.741692)
		(end 279.816814 -249.166634)
		(width 0.18288)
		(layer "In4.Cu")
		(net "M_C_CPU0_SB_CA<4>")
	)
	(segment
		(start 321.266058 -249.732038)
		(end 313.866276 -249.732038)
		(width 0.18288)
		(layer "In4.Cu")
		(net "M_C_CPU0_SB_CA<4>")
	)
	(segment
		(start 309.629556 -249.59183)
		(end 293.17061 -249.59183)
		(width 0.18288)
		(layer "In4.Cu")
		(net "M_C_CPU0_SB_CA<4>")
	)
	(segment
		(start 331.004418 -248.189496)
		(end 330.190602 -248.189496)
		(width 0.18288)
		(layer "In4.Cu")
		(net "M_C_CPU0_SB_CA<4>")
	)
	(segment
		(start 337.307682 -246.040148)
		(end 337.29295 -246.048784)
		(width 0.088646)
		(layer "In4.Cu")
		(net "M_C_CPU0_SB_CA<4>")
	)
	(segment
		(start 336.367882 -246.040148)
		(end 336.357468 -246.046244)
		(width 0.088646)
		(layer "In4.Cu")
		(net "M_C_CPU0_SB_CA<4>")
	)
	(segment
		(start 313.866022 -249.732292)
		(end 311.77103 -249.732292)
		(width 0.18288)
		(layer "In4.Cu")
		(net "M_C_CPU0_SB_CA<4>")
	)
	(segment
		(start 309.78856 -249.432826)
		(end 309.629556 -249.59183)
		(width 0.18288)
		(layer "In4.Cu")
		(net "M_C_CPU0_SB_CA<4>")
	)
	(segment
		(start 332.068424 -248.189496)
		(end 331.004418 -248.189496)
		(width 0.088646)
		(layer "In4.Cu")
		(net "M_C_CPU0_SB_CA<4>")
	)
	(segment
		(start 339.279484 -245.9863)
		(end 339.187282 -246.040148)
		(width 0.088646)
		(layer "In4.Cu")
		(net "M_C_CPU0_SB_CA<4>")
	)
	(segment
		(start 311.471564 -249.432826)
		(end 309.78856 -249.432826)
		(width 0.18288)
		(layer "In4.Cu")
		(net "M_C_CPU0_SB_CA<4>")
	)
	(segment
		(start 330.190602 -248.189496)
		(end 329.845416 -247.84431)
		(width 0.18288)
		(layer "In4.Cu")
		(net "M_C_CPU0_SB_CA<4>")
	)
	(segment
		(start 335.240884 -246.364506)
		(end 335.240884 -246.374412)
		(width 0.088646)
		(layer "In4.Cu")
		(net "M_C_CPU0_SB_CA<4>")
	)
	(segment
		(start 284.945836 -249.590052)
		(end 284.097476 -248.741692)
		(width 0.18288)
		(layer "In4.Cu")
		(net "M_C_CPU0_SB_CA<4>")
	)
	(segment
		(start 293.168832 -249.590052)
		(end 284.945836 -249.590052)
		(width 0.18288)
		(layer "In4.Cu")
		(net "M_C_CPU0_SB_CA<4>")
	)
	(segment
		(start 335.428336 -246.040148)
		(end 335.419446 -246.045228)
		(width 0.088646)
		(layer "In4.Cu")
		(net "M_C_CPU0_SB_CA<4>")
	)
	(segment
		(start 334.770984 -247.178322)
		(end 334.770984 -247.188228)
		(width 0.088646)
		(layer "In4.Cu")
		(net "M_C_CPU0_SB_CA<4>")
	)
	(segment
		(start 338.247482 -246.040148)
		(end 338.23275 -246.048784)
		(width 0.088646)
		(layer "In4.Cu")
		(net "M_C_CPU0_SB_CA<4>")
	)
	(segment
		(start 284.097476 -248.741692)
		(end 280.241756 -248.741692)
		(width 0.18288)
		(layer "In4.Cu")
		(net "M_C_CPU0_SB_CA<4>")
	)
	(arc
		(start 337.682078 -246.040148)
		(mid 337.49488 -245.990005)
		(end 337.307682 -246.040148)
		(width 0.088646)
		(layer "In4.Cu")
		(net "M_C_CPU0_SB_CA<4>")
	)
	(arc
		(start 338.621878 -246.040148)
		(mid 338.43468 -245.990005)
		(end 338.247482 -246.040148)
		(width 0.088646)
		(layer "In4.Cu")
		(net "M_C_CPU0_SB_CA<4>")
	)
	(arc
		(start 338.23275 -246.048784)
		(mid 337.956275 -246.116104)
		(end 337.682078 -246.040148)
		(width 0.088646)
		(layer "In4.Cu")
		(net "M_C_CPU0_SB_CA<4>")
	)
	(arc
		(start 335.419446 -246.045228)
		(mid 335.288532 -246.181588)
		(end 335.240884 -246.364506)
		(width 0.088646)
		(layer "In4.Cu")
		(net "M_C_CPU0_SB_CA<4>")
	)
	(arc
		(start 333.923132 -247.66778)
		(mid 333.735934 -247.617637)
		(end 333.548736 -247.66778)
		(width 0.088646)
		(layer "In4.Cu")
		(net "M_C_CPU0_SB_CA<4>")
	)
	(arc
		(start 336.357468 -246.046244)
		(mid 336.07929 -246.115967)
		(end 335.802732 -246.040148)
		(width 0.088646)
		(layer "In4.Cu")
		(net "M_C_CPU0_SB_CA<4>")
	)
	(arc
		(start 335.802732 -246.040148)
		(mid 335.615534 -245.990005)
		(end 335.428336 -246.040148)
		(width 0.088646)
		(layer "In4.Cu")
		(net "M_C_CPU0_SB_CA<4>")
	)
	(arc
		(start 339.844634 -245.55069)
		(mid 339.576091 -245.7867)
		(end 339.279484 -245.9863)
		(width 0.088646)
		(layer "In4.Cu")
		(net "M_C_CPU0_SB_CA<4>")
	)
	(arc
		(start 337.29295 -246.048784)
		(mid 337.016475 -246.116104)
		(end 336.742278 -246.040148)
		(width 0.088646)
		(layer "In4.Cu")
		(net "M_C_CPU0_SB_CA<4>")
	)
	(arc
		(start 335.240884 -246.374412)
		(mid 335.162773 -246.651361)
		(end 334.958436 -246.853964)
		(width 0.088646)
		(layer "In4.Cu")
		(net "M_C_CPU0_SB_CA<4>")
	)
	(arc
		(start 332.608936 -247.66778)
		(mid 332.568006 -247.694813)
		(end 332.530958 -247.726962)
		(width 0.088646)
		(layer "In4.Cu")
		(net "M_C_CPU0_SB_CA<4>")
	)
	(arc
		(start 332.983332 -247.66778)
		(mid 332.796134 -247.617637)
		(end 332.608936 -247.66778)
		(width 0.088646)
		(layer "In4.Cu")
		(net "M_C_CPU0_SB_CA<4>")
	)
	(arc
		(start 334.949546 -246.859044)
		(mid 334.818632 -246.995404)
		(end 334.770984 -247.178322)
		(width 0.088646)
		(layer "In4.Cu")
		(net "M_C_CPU0_SB_CA<4>")
	)
	(arc
		(start 333.548736 -247.66778)
		(mid 333.266034 -247.743556)
		(end 332.983332 -247.66778)
		(width 0.088646)
		(layer "In4.Cu")
		(net "M_C_CPU0_SB_CA<4>")
	)
	(arc
		(start 334.488536 -247.66778)
		(mid 334.205834 -247.743556)
		(end 333.923132 -247.66778)
		(width 0.088646)
		(layer "In4.Cu")
		(net "M_C_CPU0_SB_CA<4>")
	)
	(arc
		(start 334.770984 -247.188228)
		(mid 334.692873 -247.465177)
		(end 334.488536 -247.66778)
		(width 0.088646)
		(layer "In4.Cu")
		(net "M_C_CPU0_SB_CA<4>")
	)
	(arc
		(start 336.742278 -246.040148)
		(mid 336.55508 -245.990005)
		(end 336.367882 -246.040148)
		(width 0.088646)
		(layer "In4.Cu")
		(net "M_C_CPU0_SB_CA<4>")
	)
	(arc
		(start 339.187282 -246.040148)
		(mid 338.90458 -246.115924)
		(end 338.621878 -246.040148)
		(width 0.088646)
		(layer "In4.Cu")
		(net "M_C_CPU0_SB_CA<4>")
	)
	(segment
		(start 281.129994 -250.012454)
		(end 280.73477 -250.012454)
		(width 0.20066)
		(layer "F.Cu")
		(net "M_C_CPU0_SB_CA<3>")
	)
	(segment
		(start 341.25408 -246.900192)
		(end 341.25408 -246.364506)
		(width 0.20066)
		(layer "F.Cu")
		(net "M_C_CPU0_SB_CA<3>")
	)
	(segment
		(start 280.457148 -250.441714)
		(end 279.912826 -250.441714)
		(width 0.20066)
		(layer "F.Cu")
		(net "M_C_CPU0_SB_CA<3>")
	)
	(segment
		(start 282.811982 -250.016772)
		(end 281.99588 -250.016772)
		(width 0.20066)
		(layer "F.Cu")
		(net "M_C_CPU0_SB_CA<3>")
	)
	(segment
		(start 277.839932 -250.441714)
		(end 277.601934 -250.441714)
		(width 0.101854)
		(layer "F.Cu")
		(net "M_C_CPU0_SB_CA<3>")
	)
	(segment
		(start 277.233888 -250.455938)
		(end 277.091394 -250.313444)
		(width 0.20066)
		(layer "F.Cu")
		(net "M_C_CPU0_SB_CA<3>")
	)
	(segment
		(start 283.916882 -250.016772)
		(end 282.811982 -250.016772)
		(width 0.20066)
		(layer "F.Cu")
		(net "M_C_CPU0_SB_CA<3>")
	)
	(segment
		(start 280.73477 -250.012454)
		(end 280.606246 -250.140978)
		(width 0.20066)
		(layer "F.Cu")
		(net "M_C_CPU0_SB_CA<3>")
	)
	(segment
		(start 281.99588 -250.016772)
		(end 281.788362 -250.22429)
		(width 0.20066)
		(layer "F.Cu")
		(net "M_C_CPU0_SB_CA<3>")
	)
	(segment
		(start 281.34183 -250.22429)
		(end 281.129994 -250.012454)
		(width 0.20066)
		(layer "F.Cu")
		(net "M_C_CPU0_SB_CA<3>")
	)
	(segment
		(start 280.606246 -250.292616)
		(end 280.457148 -250.441714)
		(width 0.20066)
		(layer "F.Cu")
		(net "M_C_CPU0_SB_CA<3>")
	)
	(segment
		(start 279.912826 -250.441714)
		(end 277.839932 -250.441714)
		(width 0.1016)
		(layer "F.Cu")
		(net "M_C_CPU0_SB_CA<3>")
	)
	(segment
		(start 277.091394 -250.313444)
		(end 277.091394 -250.142756)
		(width 0.20066)
		(layer "F.Cu")
		(net "M_C_CPU0_SB_CA<3>")
	)
	(segment
		(start 280.606246 -250.140978)
		(end 280.606246 -250.292616)
		(width 0.20066)
		(layer "F.Cu")
		(net "M_C_CPU0_SB_CA<3>")
	)
	(segment
		(start 276.96541 -250.016772)
		(end 275.268182 -250.016772)
		(width 0.20066)
		(layer "F.Cu")
		(net "M_C_CPU0_SB_CA<3>")
	)
	(segment
		(start 281.788362 -250.22429)
		(end 281.34183 -250.22429)
		(width 0.20066)
		(layer "F.Cu")
		(net "M_C_CPU0_SB_CA<3>")
	)
	(segment
		(start 277.601934 -250.441714)
		(end 277.58771 -250.455938)
		(width 0.101854)
		(layer "F.Cu")
		(net "M_C_CPU0_SB_CA<3>")
	)
	(segment
		(start 277.58771 -250.455938)
		(end 277.233888 -250.455938)
		(width 0.20066)
		(layer "F.Cu")
		(net "M_C_CPU0_SB_CA<3>")
	)
	(segment
		(start 341.254334 -246.900446)
		(end 341.25408 -246.900192)
		(width 0.20066)
		(layer "F.Cu")
		(net "M_C_CPU0_SB_CA<3>")
	)
	(segment
		(start 277.091394 -250.142756)
		(end 276.96541 -250.016772)
		(width 0.20066)
		(layer "F.Cu")
		(net "M_C_CPU0_SB_CA<3>")
	)
	(segment
		(start 334.871822 -248.311416)
		(end 334.862932 -248.316496)
		(width 0.088646)
		(layer "In4.Cu")
		(net "M_C_CPU0_SB_CA<3>")
	)
	(segment
		(start 305.752754 -250.433332)
		(end 305.752754 -250.5837)
		(width 0.18288)
		(layer "In4.Cu")
		(net "M_C_CPU0_SB_CA<3>")
	)
	(segment
		(start 333.66837 -248.54408)
		(end 332.851252 -248.54408)
		(width 0.088646)
		(layer "In4.Cu")
		(net "M_C_CPU0_SB_CA<3>")
	)
	(segment
		(start 341.25408 -246.364506)
		(end 340.941406 -246.364506)
		(width 0.088646)
		(layer "In4.Cu")
		(net "M_C_CPU0_SB_CA<3>")
	)
	(segment
		(start 314.737496 -250.75769)
		(end 314.296044 -250.316238)
		(width 0.18288)
		(layer "In4.Cu")
		(net "M_C_CPU0_SB_CA<3>")
	)
	(segment
		(start 305.061874 -250.433332)
		(end 304.878994 -250.250452)
		(width 0.18288)
		(layer "In4.Cu")
		(net "M_C_CPU0_SB_CA<3>")
	)
	(segment
		(start 315.124084 -250.59767)
		(end 314.964064 -250.75769)
		(width 0.18288)
		(layer "In4.Cu")
		(net "M_C_CPU0_SB_CA<3>")
	)
	(segment
		(start 309.269892 -250.250452)
		(end 308.6735 -250.250452)
		(width 0.18288)
		(layer "In4.Cu")
		(net "M_C_CPU0_SB_CA<3>")
	)
	(segment
		(start 311.64784 -250.316492)
		(end 311.272174 -249.940826)
		(width 0.18288)
		(layer "In4.Cu")
		(net "M_C_CPU0_SB_CA<3>")
	)
	(segment
		(start 303.44999 -250.441714)
		(end 284.968188 -250.441714)
		(width 0.18288)
		(layer "In4.Cu")
		(net "M_C_CPU0_SB_CA<3>")
	)
	(segment
		(start 304.878994 -250.250452)
		(end 303.641252 -250.250452)
		(width 0.18288)
		(layer "In4.Cu")
		(net "M_C_CPU0_SB_CA<3>")
	)
	(segment
		(start 310.792114 -250.100846)
		(end 310.792114 -250.413012)
		(width 0.18288)
		(layer "In4.Cu")
		(net "M_C_CPU0_SB_CA<3>")
	)
	(segment
		(start 313.866022 -250.316492)
		(end 311.64784 -250.316492)
		(width 0.18288)
		(layer "In4.Cu")
		(net "M_C_CPU0_SB_CA<3>")
	)
	(segment
		(start 308.6735 -250.250452)
		(end 308.254146 -250.669806)
		(width 0.18288)
		(layer "In4.Cu")
		(net "M_C_CPU0_SB_CA<3>")
	)
	(segment
		(start 340.941406 -246.364506)
		(end 340.875874 -246.298974)
		(width 0.088646)
		(layer "In4.Cu")
		(net "M_C_CPU0_SB_CA<3>")
	)
	(segment
		(start 308.254146 -250.669806)
		(end 307.531262 -250.669806)
		(width 0.18288)
		(layer "In4.Cu")
		(net "M_C_CPU0_SB_CA<3>")
	)
	(segment
		(start 315.284104 -250.316238)
		(end 315.124084 -250.476258)
		(width 0.18288)
		(layer "In4.Cu")
		(net "M_C_CPU0_SB_CA<3>")
	)
	(segment
		(start 335.341722 -247.4976)
		(end 335.332832 -247.50268)
		(width 0.088646)
		(layer "In4.Cu")
		(net "M_C_CPU0_SB_CA<3>")
	)
	(segment
		(start 305.935634 -250.250452)
		(end 305.752754 -250.433332)
		(width 0.18288)
		(layer "In4.Cu")
		(net "M_C_CPU0_SB_CA<3>")
	)
	(segment
		(start 337.307682 -246.688864)
		(end 337.29295 -246.680228)
		(width 0.088646)
		(layer "In4.Cu")
		(net "M_C_CPU0_SB_CA<3>")
	)
	(segment
		(start 307.531262 -250.669806)
		(end 307.111908 -250.250452)
		(width 0.18288)
		(layer "In4.Cu")
		(net "M_C_CPU0_SB_CA<3>")
	)
	(segment
		(start 310.632094 -250.573032)
		(end 309.592472 -250.573032)
		(width 0.18288)
		(layer "In4.Cu")
		(net "M_C_CPU0_SB_CA<3>")
	)
	(segment
		(start 333.806038 -248.406412)
		(end 333.66837 -248.54408)
		(width 0.088646)
		(layer "In4.Cu")
		(net "M_C_CPU0_SB_CA<3>")
	)
	(segment
		(start 340.031832 -245.875048)
		(end 340.025736 -245.878604)
		(width 0.088646)
		(layer "In4.Cu")
		(net "M_C_CPU0_SB_CA<3>")
	)
	(segment
		(start 313.866276 -250.316238)
		(end 313.866022 -250.316492)
		(width 0.18288)
		(layer "In4.Cu")
		(net "M_C_CPU0_SB_CA<3>")
	)
	(segment
		(start 284.359604 -249.83313)
		(end 284.100524 -249.83313)
		(width 0.18288)
		(layer "In4.Cu")
		(net "M_C_CPU0_SB_CA<3>")
	)
	(segment
		(start 314.964064 -250.75769)
		(end 314.737496 -250.75769)
		(width 0.18288)
		(layer "In4.Cu")
		(net "M_C_CPU0_SB_CA<3>")
	)
	(segment
		(start 311.272174 -249.940826)
		(end 310.952134 -249.940826)
		(width 0.18288)
		(layer "In4.Cu")
		(net "M_C_CPU0_SB_CA<3>")
	)
	(segment
		(start 339.187282 -246.688864)
		(end 339.17255 -246.680228)
		(width 0.088646)
		(layer "In4.Cu")
		(net "M_C_CPU0_SB_CA<3>")
	)
	(segment
		(start 335.520284 -247.168416)
		(end 335.520284 -247.178322)
		(width 0.088646)
		(layer "In4.Cu")
		(net "M_C_CPU0_SB_CA<3>")
	)
	(segment
		(start 305.244754 -250.76658)
		(end 305.061874 -250.5837)
		(width 0.18288)
		(layer "In4.Cu")
		(net "M_C_CPU0_SB_CA<3>")
	)
	(segment
		(start 332.851252 -248.54408)
		(end 332.742286 -248.653046)
		(width 0.088646)
		(layer "In4.Cu")
		(net "M_C_CPU0_SB_CA<3>")
	)
	(segment
		(start 310.792114 -250.413012)
		(end 310.632094 -250.573032)
		(width 0.18288)
		(layer "In4.Cu")
		(net "M_C_CPU0_SB_CA<3>")
	)
	(segment
		(start 314.296044 -250.316238)
		(end 313.866276 -250.316238)
		(width 0.18288)
		(layer "In4.Cu")
		(net "M_C_CPU0_SB_CA<3>")
	)
	(segment
		(start 335.050384 -247.982232)
		(end 335.050384 -247.992138)
		(width 0.088646)
		(layer "In4.Cu")
		(net "M_C_CPU0_SB_CA<3>")
	)
	(segment
		(start 340.042246 -245.868952)
		(end 340.031832 -245.875048)
		(width 0.088646)
		(layer "In4.Cu")
		(net "M_C_CPU0_SB_CA<3>")
	)
	(segment
		(start 330.171552 -249.14733)
		(end 329.203812 -248.17959)
		(width 0.18288)
		(layer "In4.Cu")
		(net "M_C_CPU0_SB_CA<3>")
	)
	(segment
		(start 321.540886 -250.316238)
		(end 315.284104 -250.316238)
		(width 0.18288)
		(layer "In4.Cu")
		(net "M_C_CPU0_SB_CA<3>")
	)
	(segment
		(start 323.677534 -248.17959)
		(end 321.540886 -250.316238)
		(width 0.18288)
		(layer "In4.Cu")
		(net "M_C_CPU0_SB_CA<3>")
	)
	(segment
		(start 305.569874 -250.76658)
		(end 305.244754 -250.76658)
		(width 0.18288)
		(layer "In4.Cu")
		(net "M_C_CPU0_SB_CA<3>")
	)
	(segment
		(start 332.742286 -248.653046)
		(end 332.248002 -249.14733)
		(width 0.18288)
		(layer "In4.Cu")
		(net "M_C_CPU0_SB_CA<3>")
	)
	(segment
		(start 284.100524 -249.83313)
		(end 283.916882 -250.016772)
		(width 0.18288)
		(layer "In4.Cu")
		(net "M_C_CPU0_SB_CA<3>")
	)
	(segment
		(start 284.968188 -250.441714)
		(end 284.359604 -249.83313)
		(width 0.18288)
		(layer "In4.Cu")
		(net "M_C_CPU0_SB_CA<3>")
	)
	(segment
		(start 309.592472 -250.573032)
		(end 309.269892 -250.250452)
		(width 0.18288)
		(layer "In4.Cu")
		(net "M_C_CPU0_SB_CA<3>")
	)
	(segment
		(start 303.641252 -250.250452)
		(end 303.44999 -250.441714)
		(width 0.18288)
		(layer "In4.Cu")
		(net "M_C_CPU0_SB_CA<3>")
	)
	(segment
		(start 305.752754 -250.5837)
		(end 305.569874 -250.76658)
		(width 0.18288)
		(layer "In4.Cu")
		(net "M_C_CPU0_SB_CA<3>")
	)
	(segment
		(start 339.570568 -246.683784)
		(end 339.561678 -246.688864)
		(width 0.088646)
		(layer "In4.Cu")
		(net "M_C_CPU0_SB_CA<3>")
	)
	(segment
		(start 336.367882 -246.688864)
		(end 336.357468 -246.682768)
		(width 0.088646)
		(layer "In4.Cu")
		(net "M_C_CPU0_SB_CA<3>")
	)
	(segment
		(start 315.124084 -250.476258)
		(end 315.124084 -250.59767)
		(width 0.18288)
		(layer "In4.Cu")
		(net "M_C_CPU0_SB_CA<3>")
	)
	(segment
		(start 332.248002 -249.14733)
		(end 330.171552 -249.14733)
		(width 0.18288)
		(layer "In4.Cu")
		(net "M_C_CPU0_SB_CA<3>")
	)
	(segment
		(start 307.111908 -250.250452)
		(end 305.935634 -250.250452)
		(width 0.18288)
		(layer "In4.Cu")
		(net "M_C_CPU0_SB_CA<3>")
	)
	(segment
		(start 329.203812 -248.17959)
		(end 323.677534 -248.17959)
		(width 0.18288)
		(layer "In4.Cu")
		(net "M_C_CPU0_SB_CA<3>")
	)
	(segment
		(start 305.061874 -250.5837)
		(end 305.061874 -250.433332)
		(width 0.18288)
		(layer "In4.Cu")
		(net "M_C_CPU0_SB_CA<3>")
	)
	(segment
		(start 310.952134 -249.940826)
		(end 310.792114 -250.100846)
		(width 0.18288)
		(layer "In4.Cu")
		(net "M_C_CPU0_SB_CA<3>")
	)
	(arc
		(start 334.862932 -248.316496)
		(mid 334.675734 -248.366639)
		(end 334.488536 -248.316496)
		(width 0.088646)
		(layer "In4.Cu")
		(net "M_C_CPU0_SB_CA<3>")
	)
	(arc
		(start 340.025736 -245.878604)
		(mid 339.823149 -246.084955)
		(end 339.74913 -246.364506)
		(width 0.088646)
		(layer "In4.Cu")
		(net "M_C_CPU0_SB_CA<3>")
	)
	(arc
		(start 335.332832 -247.50268)
		(mid 335.128497 -247.705285)
		(end 335.050384 -247.982232)
		(width 0.088646)
		(layer "In4.Cu")
		(net "M_C_CPU0_SB_CA<3>")
	)
	(arc
		(start 339.74913 -246.364506)
		(mid 339.701451 -246.547406)
		(end 339.570568 -246.683784)
		(width 0.088646)
		(layer "In4.Cu")
		(net "M_C_CPU0_SB_CA<3>")
	)
	(arc
		(start 339.17255 -246.680228)
		(mid 338.896075 -246.612908)
		(end 338.621878 -246.688864)
		(width 0.088646)
		(layer "In4.Cu")
		(net "M_C_CPU0_SB_CA<3>")
	)
	(arc
		(start 338.621878 -246.688864)
		(mid 338.43468 -246.739007)
		(end 338.247482 -246.688864)
		(width 0.088646)
		(layer "In4.Cu")
		(net "M_C_CPU0_SB_CA<3>")
	)
	(arc
		(start 339.561678 -246.688864)
		(mid 339.37448 -246.739007)
		(end 339.187282 -246.688864)
		(width 0.088646)
		(layer "In4.Cu")
		(net "M_C_CPU0_SB_CA<3>")
	)
	(arc
		(start 340.875874 -246.298974)
		(mid 340.7867 -246.053932)
		(end 340.596982 -245.875048)
		(width 0.088646)
		(layer "In4.Cu")
		(net "M_C_CPU0_SB_CA<3>")
	)
	(arc
		(start 335.050384 -247.992138)
		(mid 335.002705 -248.175038)
		(end 334.871822 -248.311416)
		(width 0.088646)
		(layer "In4.Cu")
		(net "M_C_CPU0_SB_CA<3>")
	)
	(arc
		(start 337.29295 -246.680228)
		(mid 337.016475 -246.612908)
		(end 336.742278 -246.688864)
		(width 0.088646)
		(layer "In4.Cu")
		(net "M_C_CPU0_SB_CA<3>")
	)
	(arc
		(start 335.802732 -246.688864)
		(mid 335.598397 -246.891469)
		(end 335.520284 -247.168416)
		(width 0.088646)
		(layer "In4.Cu")
		(net "M_C_CPU0_SB_CA<3>")
	)
	(arc
		(start 340.596982 -245.875048)
		(mid 340.320423 -245.799305)
		(end 340.042246 -245.868952)
		(width 0.088646)
		(layer "In4.Cu")
		(net "M_C_CPU0_SB_CA<3>")
	)
	(arc
		(start 335.520284 -247.178322)
		(mid 335.472605 -247.361222)
		(end 335.341722 -247.4976)
		(width 0.088646)
		(layer "In4.Cu")
		(net "M_C_CPU0_SB_CA<3>")
	)
	(arc
		(start 336.742278 -246.688864)
		(mid 336.55508 -246.739007)
		(end 336.367882 -246.688864)
		(width 0.088646)
		(layer "In4.Cu")
		(net "M_C_CPU0_SB_CA<3>")
	)
	(arc
		(start 338.247482 -246.688864)
		(mid 337.96478 -246.613088)
		(end 337.682078 -246.688864)
		(width 0.088646)
		(layer "In4.Cu")
		(net "M_C_CPU0_SB_CA<3>")
	)
	(arc
		(start 337.682078 -246.688864)
		(mid 337.49488 -246.739007)
		(end 337.307682 -246.688864)
		(width 0.088646)
		(layer "In4.Cu")
		(net "M_C_CPU0_SB_CA<3>")
	)
	(arc
		(start 336.357468 -246.682768)
		(mid 336.07929 -246.613045)
		(end 335.802732 -246.688864)
		(width 0.088646)
		(layer "In4.Cu")
		(net "M_C_CPU0_SB_CA<3>")
	)
	(arc
		(start 334.488536 -248.316496)
		(mid 334.132013 -248.245593)
		(end 333.806038 -248.406412)
		(width 0.088646)
		(layer "In4.Cu")
		(net "M_C_CPU0_SB_CA<3>")
	)
	(segment
		(start 279.816814 -250.866656)
		(end 278.711914 -250.866656)
		(width 0.20066)
		(layer "F.Cu")
		(net "M_C_CPU0_SB_CA<2>")
	)
	(segment
		(start 276.469094 -250.441714)
		(end 276.138386 -250.441714)
		(width 0.101854)
		(layer "F.Cu")
		(net "M_C_CPU0_SB_CA<2>")
	)
	(segment
		(start 274.152868 -250.441714)
		(end 274.143978 -250.432824)
		(width 0.1016)
		(layer "F.Cu")
		(net "M_C_CPU0_SB_CA<2>")
	)
	(segment
		(start 278.711914 -250.866656)
		(end 277.072598 -250.866656)
		(width 0.20066)
		(layer "F.Cu")
		(net "M_C_CPU0_SB_CA<2>")
	)
	(segment
		(start 272.713704 -251.077984)
		(end 272.502376 -250.866656)
		(width 0.20066)
		(layer "F.Cu")
		(net "M_C_CPU0_SB_CA<2>")
	)
	(segment
		(start 277.072598 -250.866656)
		(end 276.647656 -250.441714)
		(width 0.20066)
		(layer "F.Cu")
		(net "M_C_CPU0_SB_CA<2>")
	)
	(segment
		(start 274.143978 -250.432824)
		(end 273.53514 -250.432824)
		(width 0.20066)
		(layer "F.Cu")
		(net "M_C_CPU0_SB_CA<2>")
	)
	(segment
		(start 273.37258 -250.923552)
		(end 273.218148 -251.077984)
		(width 0.20066)
		(layer "F.Cu")
		(net "M_C_CPU0_SB_CA<2>")
	)
	(segment
		(start 272.502376 -250.866656)
		(end 271.168114 -250.866656)
		(width 0.20066)
		(layer "F.Cu")
		(net "M_C_CPU0_SB_CA<2>")
	)
	(segment
		(start 273.37258 -250.595384)
		(end 273.37258 -250.923552)
		(width 0.20066)
		(layer "F.Cu")
		(net "M_C_CPU0_SB_CA<2>")
	)
	(segment
		(start 273.53514 -250.432824)
		(end 273.37258 -250.595384)
		(width 0.20066)
		(layer "F.Cu")
		(net "M_C_CPU0_SB_CA<2>")
	)
	(segment
		(start 340.314534 -246.900446)
		(end 340.31428 -246.900192)
		(width 0.20066)
		(layer "F.Cu")
		(net "M_C_CPU0_SB_CA<2>")
	)
	(segment
		(start 340.31428 -246.900192)
		(end 340.31428 -246.364506)
		(width 0.20066)
		(layer "F.Cu")
		(net "M_C_CPU0_SB_CA<2>")
	)
	(segment
		(start 276.647656 -250.441714)
		(end 276.469094 -250.441714)
		(width 0.20066)
		(layer "F.Cu")
		(net "M_C_CPU0_SB_CA<2>")
	)
	(segment
		(start 273.218148 -251.077984)
		(end 272.713704 -251.077984)
		(width 0.20066)
		(layer "F.Cu")
		(net "M_C_CPU0_SB_CA<2>")
	)
	(segment
		(start 276.138386 -250.441714)
		(end 274.152868 -250.441714)
		(width 0.1016)
		(layer "F.Cu")
		(net "M_C_CPU0_SB_CA<2>")
	)
	(segment
		(start 282.916884 -250.441714)
		(end 281.752802 -251.605796)
		(width 0.18288)
		(layer "In4.Cu")
		(net "M_C_CPU0_SB_CA<2>")
	)
	(segment
		(start 333.940658 -248.541032)
		(end 333.67091 -248.81078)
		(width 0.088646)
		(layer "In4.Cu")
		(net "M_C_CPU0_SB_CA<2>")
	)
	(segment
		(start 313.866022 -251.420884)
		(end 311.40146 -251.420884)
		(width 0.18288)
		(layer "In4.Cu")
		(net "M_C_CPU0_SB_CA<2>")
	)
	(segment
		(start 305.519074 -251.600208)
		(end 305.13655 -251.600208)
		(width 0.18288)
		(layer "In4.Cu")
		(net "M_C_CPU0_SB_CA<2>")
	)
	(segment
		(start 339.93963 -246.364506)
		(end 339.93963 -246.374412)
		(width 0.088646)
		(layer "In4.Cu")
		(net "M_C_CPU0_SB_CA<2>")
	)
	(segment
		(start 333.67091 -248.81078)
		(end 333.325216 -248.81078)
		(width 0.088646)
		(layer "In4.Cu")
		(net "M_C_CPU0_SB_CA<2>")
	)
	(segment
		(start 339.102446 -246.86006)
		(end 339.092032 -246.853964)
		(width 0.088646)
		(layer "In4.Cu")
		(net "M_C_CPU0_SB_CA<2>")
	)
	(segment
		(start 321.166236 -251.42063)
		(end 313.866276 -251.42063)
		(width 0.18288)
		(layer "In4.Cu")
		(net "M_C_CPU0_SB_CA<2>")
	)
	(segment
		(start 332.424786 -249.71121)
		(end 329.865736 -249.71121)
		(width 0.18288)
		(layer "In4.Cu")
		(net "M_C_CPU0_SB_CA<2>")
	)
	(segment
		(start 340.510368 -246.045228)
		(end 340.501478 -246.040148)
		(width 0.088646)
		(layer "In4.Cu")
		(net "M_C_CPU0_SB_CA<2>")
	)
	(segment
		(start 329.865736 -249.71121)
		(end 328.669396 -248.51487)
		(width 0.18288)
		(layer "In4.Cu")
		(net "M_C_CPU0_SB_CA<2>")
	)
	(segment
		(start 281.752802 -251.605796)
		(end 280.555954 -251.605796)
		(width 0.18288)
		(layer "In4.Cu")
		(net "M_C_CPU0_SB_CA<2>")
	)
	(segment
		(start 309.720742 -251.109226)
		(end 309.538116 -251.291852)
		(width 0.18288)
		(layer "In4.Cu")
		(net "M_C_CPU0_SB_CA<2>")
	)
	(segment
		(start 338.162392 -246.86006)
		(end 338.151978 -246.853964)
		(width 0.088646)
		(layer "In4.Cu")
		(net "M_C_CPU0_SB_CA<2>")
	)
	(segment
		(start 335.898236 -246.853964)
		(end 335.889346 -246.859044)
		(width 0.088646)
		(layer "In4.Cu")
		(net "M_C_CPU0_SB_CA<2>")
	)
	(segment
		(start 328.669396 -248.51487)
		(end 324.071996 -248.51487)
		(width 0.18288)
		(layer "In4.Cu")
		(net "M_C_CPU0_SB_CA<2>")
	)
	(segment
		(start 284.237684 -250.441714)
		(end 282.916884 -250.441714)
		(width 0.18288)
		(layer "In4.Cu")
		(net "M_C_CPU0_SB_CA<2>")
	)
	(segment
		(start 335.240884 -247.992138)
		(end 335.240884 -248.01068)
		(width 0.088646)
		(layer "In4.Cu")
		(net "M_C_CPU0_SB_CA<2>")
	)
	(segment
		(start 280.555954 -251.605796)
		(end 279.816814 -250.866656)
		(width 0.18288)
		(layer "In4.Cu")
		(net "M_C_CPU0_SB_CA<2>")
	)
	(segment
		(start 335.710784 -247.178322)
		(end 335.710784 -247.188228)
		(width 0.088646)
		(layer "In4.Cu")
		(net "M_C_CPU0_SB_CA<2>")
	)
	(segment
		(start 304.137314 -251.600208)
		(end 303.75479 -251.600208)
		(width 0.18288)
		(layer "In4.Cu")
		(net "M_C_CPU0_SB_CA<2>")
	)
	(segment
		(start 303.446434 -251.291852)
		(end 285.087822 -251.291852)
		(width 0.18288)
		(layer "In4.Cu")
		(net "M_C_CPU0_SB_CA<2>")
	)
	(segment
		(start 309.538116 -251.291852)
		(end 305.82743 -251.291852)
		(width 0.18288)
		(layer "In4.Cu")
		(net "M_C_CPU0_SB_CA<2>")
	)
	(segment
		(start 335.428336 -247.66778)
		(end 335.419446 -247.67286)
		(width 0.088646)
		(layer "In4.Cu")
		(net "M_C_CPU0_SB_CA<2>")
	)
	(segment
		(start 324.071996 -248.51487)
		(end 321.166236 -251.42063)
		(width 0.18288)
		(layer "In4.Cu")
		(net "M_C_CPU0_SB_CA<2>")
	)
	(segment
		(start 311.40146 -251.420884)
		(end 311.089802 -251.109226)
		(width 0.18288)
		(layer "In4.Cu")
		(net "M_C_CPU0_SB_CA<2>")
	)
	(segment
		(start 305.82743 -251.291852)
		(end 305.519074 -251.600208)
		(width 0.18288)
		(layer "In4.Cu")
		(net "M_C_CPU0_SB_CA<2>")
	)
	(segment
		(start 304.44567 -251.291852)
		(end 304.137314 -251.600208)
		(width 0.18288)
		(layer "In4.Cu")
		(net "M_C_CPU0_SB_CA<2>")
	)
	(segment
		(start 336.287364 -246.8626)
		(end 336.272632 -246.853964)
		(width 0.088646)
		(layer "In4.Cu")
		(net "M_C_CPU0_SB_CA<2>")
	)
	(segment
		(start 311.089802 -251.109226)
		(end 309.720742 -251.109226)
		(width 0.18288)
		(layer "In4.Cu")
		(net "M_C_CPU0_SB_CA<2>")
	)
	(segment
		(start 313.866276 -251.42063)
		(end 313.866022 -251.420884)
		(width 0.18288)
		(layer "In4.Cu")
		(net "M_C_CPU0_SB_CA<2>")
	)
	(segment
		(start 285.087822 -251.291852)
		(end 284.237684 -250.441714)
		(width 0.18288)
		(layer "In4.Cu")
		(net "M_C_CPU0_SB_CA<2>")
	)
	(segment
		(start 333.325216 -248.81078)
		(end 333.112618 -249.023378)
		(width 0.088646)
		(layer "In4.Cu")
		(net "M_C_CPU0_SB_CA<2>")
	)
	(segment
		(start 337.222846 -246.86006)
		(end 337.212432 -246.853964)
		(width 0.088646)
		(layer "In4.Cu")
		(net "M_C_CPU0_SB_CA<2>")
	)
	(segment
		(start 340.626954 -246.364506)
		(end 340.684358 -246.307102)
		(width 0.088646)
		(layer "In4.Cu")
		(net "M_C_CPU0_SB_CA<2>")
	)
	(segment
		(start 303.75479 -251.600208)
		(end 303.446434 -251.291852)
		(width 0.18288)
		(layer "In4.Cu")
		(net "M_C_CPU0_SB_CA<2>")
	)
	(segment
		(start 333.112618 -249.023378)
		(end 332.424786 -249.71121)
		(width 0.18288)
		(layer "In4.Cu")
		(net "M_C_CPU0_SB_CA<2>")
	)
	(segment
		(start 304.828194 -251.291852)
		(end 304.44567 -251.291852)
		(width 0.18288)
		(layer "In4.Cu")
		(net "M_C_CPU0_SB_CA<2>")
	)
	(segment
		(start 340.127082 -246.040148)
		(end 340.118192 -246.045228)
		(width 0.088646)
		(layer "In4.Cu")
		(net "M_C_CPU0_SB_CA<2>")
	)
	(segment
		(start 305.13655 -251.600208)
		(end 304.828194 -251.291852)
		(width 0.18288)
		(layer "In4.Cu")
		(net "M_C_CPU0_SB_CA<2>")
	)
	(segment
		(start 340.31428 -246.364506)
		(end 340.626954 -246.364506)
		(width 0.088646)
		(layer "In4.Cu")
		(net "M_C_CPU0_SB_CA<2>")
	)
	(arc
		(start 340.118192 -246.045228)
		(mid 339.987278 -246.181588)
		(end 339.93963 -246.364506)
		(width 0.088646)
		(layer "In4.Cu")
		(net "M_C_CPU0_SB_CA<2>")
	)
	(arc
		(start 338.151978 -246.853964)
		(mid 337.96478 -246.803821)
		(end 337.777582 -246.853964)
		(width 0.088646)
		(layer "In4.Cu")
		(net "M_C_CPU0_SB_CA<2>")
	)
	(arc
		(start 335.240884 -248.01068)
		(mid 335.160722 -248.282869)
		(end 334.958436 -248.48185)
		(width 0.088646)
		(layer "In4.Cu")
		(net "M_C_CPU0_SB_CA<2>")
	)
	(arc
		(start 340.501478 -246.040148)
		(mid 340.31428 -245.990005)
		(end 340.127082 -246.040148)
		(width 0.088646)
		(layer "In4.Cu")
		(net "M_C_CPU0_SB_CA<2>")
	)
	(arc
		(start 334.018636 -248.48185)
		(mid 333.977706 -248.508883)
		(end 333.940658 -248.541032)
		(width 0.088646)
		(layer "In4.Cu")
		(net "M_C_CPU0_SB_CA<2>")
	)
	(arc
		(start 339.93963 -246.374412)
		(mid 339.861519 -246.651361)
		(end 339.657182 -246.853964)
		(width 0.088646)
		(layer "In4.Cu")
		(net "M_C_CPU0_SB_CA<2>")
	)
	(arc
		(start 334.958436 -248.48185)
		(mid 334.675734 -248.557592)
		(end 334.393032 -248.48185)
		(width 0.088646)
		(layer "In4.Cu")
		(net "M_C_CPU0_SB_CA<2>")
	)
	(arc
		(start 335.710784 -247.188228)
		(mid 335.632673 -247.465177)
		(end 335.428336 -247.66778)
		(width 0.088646)
		(layer "In4.Cu")
		(net "M_C_CPU0_SB_CA<2>")
	)
	(arc
		(start 335.889346 -246.859044)
		(mid 335.758432 -246.995404)
		(end 335.710784 -247.178322)
		(width 0.088646)
		(layer "In4.Cu")
		(net "M_C_CPU0_SB_CA<2>")
	)
	(arc
		(start 338.717636 -246.853964)
		(mid 338.440823 -246.929834)
		(end 338.162392 -246.86006)
		(width 0.088646)
		(layer "In4.Cu")
		(net "M_C_CPU0_SB_CA<2>")
	)
	(arc
		(start 337.212432 -246.853964)
		(mid 337.025234 -246.803821)
		(end 336.838036 -246.853964)
		(width 0.088646)
		(layer "In4.Cu")
		(net "M_C_CPU0_SB_CA<2>")
	)
	(arc
		(start 336.838036 -246.853964)
		(mid 336.563837 -246.929799)
		(end 336.287364 -246.8626)
		(width 0.088646)
		(layer "In4.Cu")
		(net "M_C_CPU0_SB_CA<2>")
	)
	(arc
		(start 335.419446 -247.67286)
		(mid 335.288532 -247.80922)
		(end 335.240884 -247.992138)
		(width 0.088646)
		(layer "In4.Cu")
		(net "M_C_CPU0_SB_CA<2>")
	)
	(arc
		(start 334.393032 -248.48185)
		(mid 334.205834 -248.431707)
		(end 334.018636 -248.48185)
		(width 0.088646)
		(layer "In4.Cu")
		(net "M_C_CPU0_SB_CA<2>")
	)
	(arc
		(start 337.777582 -246.853964)
		(mid 337.501023 -246.929707)
		(end 337.222846 -246.86006)
		(width 0.088646)
		(layer "In4.Cu")
		(net "M_C_CPU0_SB_CA<2>")
	)
	(arc
		(start 339.657182 -246.853964)
		(mid 339.380623 -246.929707)
		(end 339.102446 -246.86006)
		(width 0.088646)
		(layer "In4.Cu")
		(net "M_C_CPU0_SB_CA<2>")
	)
	(arc
		(start 336.272632 -246.853964)
		(mid 336.085434 -246.803821)
		(end 335.898236 -246.853964)
		(width 0.088646)
		(layer "In4.Cu")
		(net "M_C_CPU0_SB_CA<2>")
	)
	(arc
		(start 340.684358 -246.307102)
		(mid 340.626202 -246.156989)
		(end 340.510368 -246.045228)
		(width 0.088646)
		(layer "In4.Cu")
		(net "M_C_CPU0_SB_CA<2>")
	)
	(arc
		(start 339.092032 -246.853964)
		(mid 338.904834 -246.803821)
		(end 338.717636 -246.853964)
		(width 0.088646)
		(layer "In4.Cu")
		(net "M_C_CPU0_SB_CA<2>")
	)
	(segment
		(start 276.96541 -251.716794)
		(end 275.268182 -251.716794)
		(width 0.20066)
		(layer "F.Cu")
		(net "M_C_CPU0_SB_CA<1>")
	)
	(segment
		(start 277.091394 -251.842778)
		(end 276.96541 -251.716794)
		(width 0.20066)
		(layer "F.Cu")
		(net "M_C_CPU0_SB_CA<1>")
	)
	(segment
		(start 277.233888 -252.15596)
		(end 277.091394 -252.013466)
		(width 0.20066)
		(layer "F.Cu")
		(net "M_C_CPU0_SB_CA<1>")
	)
	(segment
		(start 280.606246 -251.992638)
		(end 280.457148 -252.141736)
		(width 0.20066)
		(layer "F.Cu")
		(net "M_C_CPU0_SB_CA<1>")
	)
	(segment
		(start 281.129994 -251.712476)
		(end 280.73477 -251.712476)
		(width 0.20066)
		(layer "F.Cu")
		(net "M_C_CPU0_SB_CA<1>")
	)
	(segment
		(start 281.788362 -251.924312)
		(end 281.34183 -251.924312)
		(width 0.20066)
		(layer "F.Cu")
		(net "M_C_CPU0_SB_CA<1>")
	)
	(segment
		(start 277.839932 -252.141736)
		(end 277.601934 -252.141736)
		(width 0.101854)
		(layer "F.Cu")
		(net "M_C_CPU0_SB_CA<1>")
	)
	(segment
		(start 283.916882 -251.716794)
		(end 282.811982 -251.716794)
		(width 0.20066)
		(layer "F.Cu")
		(net "M_C_CPU0_SB_CA<1>")
	)
	(segment
		(start 277.58771 -252.15596)
		(end 277.233888 -252.15596)
		(width 0.20066)
		(layer "F.Cu")
		(net "M_C_CPU0_SB_CA<1>")
	)
	(segment
		(start 280.606246 -251.841)
		(end 280.606246 -251.992638)
		(width 0.20066)
		(layer "F.Cu")
		(net "M_C_CPU0_SB_CA<1>")
	)
	(segment
		(start 341.833962 -253.919482)
		(end 341.834216 -253.919736)
		(width 0.20066)
		(layer "F.Cu")
		(net "M_C_CPU0_SB_CA<1>")
	)
	(segment
		(start 279.912826 -252.141736)
		(end 277.839932 -252.141736)
		(width 0.1016)
		(layer "F.Cu")
		(net "M_C_CPU0_SB_CA<1>")
	)
	(segment
		(start 277.601934 -252.141736)
		(end 277.58771 -252.15596)
		(width 0.101854)
		(layer "F.Cu")
		(net "M_C_CPU0_SB_CA<1>")
	)
	(segment
		(start 280.73477 -251.712476)
		(end 280.606246 -251.841)
		(width 0.20066)
		(layer "F.Cu")
		(net "M_C_CPU0_SB_CA<1>")
	)
	(segment
		(start 277.091394 -252.013466)
		(end 277.091394 -251.842778)
		(width 0.20066)
		(layer "F.Cu")
		(net "M_C_CPU0_SB_CA<1>")
	)
	(segment
		(start 341.833962 -253.383796)
		(end 341.833962 -253.919482)
		(width 0.20066)
		(layer "F.Cu")
		(net "M_C_CPU0_SB_CA<1>")
	)
	(segment
		(start 281.99588 -251.716794)
		(end 281.788362 -251.924312)
		(width 0.20066)
		(layer "F.Cu")
		(net "M_C_CPU0_SB_CA<1>")
	)
	(segment
		(start 282.811982 -251.716794)
		(end 281.99588 -251.716794)
		(width 0.20066)
		(layer "F.Cu")
		(net "M_C_CPU0_SB_CA<1>")
	)
	(segment
		(start 281.34183 -251.924312)
		(end 281.129994 -251.712476)
		(width 0.20066)
		(layer "F.Cu")
		(net "M_C_CPU0_SB_CA<1>")
	)
	(segment
		(start 280.457148 -252.141736)
		(end 279.912826 -252.141736)
		(width 0.20066)
		(layer "F.Cu")
		(net "M_C_CPU0_SB_CA<1>")
	)
	(segment
		(start 284.343348 -252.383544)
		(end 284.173422 -251.973334)
		(width 0.18288)
		(layer "In4.Cu")
		(net "M_C_CPU0_SB_CA<1>")
	)
	(segment
		(start 341.99068 -254.190754)
		(end 342.068658 -254.211582)
		(width 0.088646)
		(layer "In4.Cu")
		(net "M_C_CPU0_SB_CA<1>")
	)
	(segment
		(start 324.785736 -249.24131)
		(end 320.860674 -253.166372)
		(width 0.18288)
		(layer "In4.Cu")
		(net "M_C_CPU0_SB_CA<1>")
	)
	(segment
		(start 342.092026 -252.036834)
		(end 340.937342 -250.88215)
		(width 0.18288)
		(layer "In4.Cu")
		(net "M_C_CPU0_SB_CA<1>")
	)
	(segment
		(start 313.866022 -253.166626)
		(end 284.56255 -253.166626)
		(width 0.18288)
		(layer "In4.Cu")
		(net "M_C_CPU0_SB_CA<1>")
	)
	(segment
		(start 313.866276 -253.166372)
		(end 313.866022 -253.166626)
		(width 0.18288)
		(layer "In4.Cu")
		(net "M_C_CPU0_SB_CA<1>")
	)
	(segment
		(start 341.834216 -253.919736)
		(end 341.99068 -254.190754)
		(width 0.088646)
		(layer "In4.Cu")
		(net "M_C_CPU0_SB_CA<1>")
	)
	(segment
		(start 342.092026 -253.513336)
		(end 342.092026 -253.035562)
		(width 0.088646)
		(layer "In4.Cu")
		(net "M_C_CPU0_SB_CA<1>")
	)
	(segment
		(start 329.244198 -250.88215)
		(end 327.603358 -249.24131)
		(width 0.18288)
		(layer "In4.Cu")
		(net "M_C_CPU0_SB_CA<1>")
	)
	(segment
		(start 342.208612 -253.629922)
		(end 342.092026 -253.513336)
		(width 0.088646)
		(layer "In4.Cu")
		(net "M_C_CPU0_SB_CA<1>")
	)
	(segment
		(start 342.208612 -253.928372)
		(end 342.208612 -253.629922)
		(width 0.088646)
		(layer "In4.Cu")
		(net "M_C_CPU0_SB_CA<1>")
	)
	(segment
		(start 342.092026 -253.035562)
		(end 342.092026 -252.036834)
		(width 0.18288)
		(layer "In4.Cu")
		(net "M_C_CPU0_SB_CA<1>")
	)
	(segment
		(start 284.56255 -253.166626)
		(end 284.343348 -252.947424)
		(width 0.18288)
		(layer "In4.Cu")
		(net "M_C_CPU0_SB_CA<1>")
	)
	(segment
		(start 284.343348 -252.947424)
		(end 284.343348 -252.383544)
		(width 0.18288)
		(layer "In4.Cu")
		(net "M_C_CPU0_SB_CA<1>")
	)
	(segment
		(start 284.173422 -251.973334)
		(end 283.916882 -251.716794)
		(width 0.18288)
		(layer "In4.Cu")
		(net "M_C_CPU0_SB_CA<1>")
	)
	(segment
		(start 340.937342 -250.88215)
		(end 329.244198 -250.88215)
		(width 0.18288)
		(layer "In4.Cu")
		(net "M_C_CPU0_SB_CA<1>")
	)
	(segment
		(start 327.603358 -249.24131)
		(end 324.785736 -249.24131)
		(width 0.18288)
		(layer "In4.Cu")
		(net "M_C_CPU0_SB_CA<1>")
	)
	(segment
		(start 320.860674 -253.166372)
		(end 313.866276 -253.166372)
		(width 0.18288)
		(layer "In4.Cu")
		(net "M_C_CPU0_SB_CA<1>")
	)
	(arc
		(start 342.068658 -254.211582)
		(mid 342.169979 -254.085461)
		(end 342.208612 -253.928372)
		(width 0.088646)
		(layer "In4.Cu")
		(net "M_C_CPU0_SB_CA<1>")
	)
	(segment
		(start 274.143978 -252.132846)
		(end 273.53514 -252.132846)
		(width 0.20066)
		(layer "F.Cu")
		(net "M_C_CPU0_SB_CA<0>")
	)
	(segment
		(start 277.072598 -252.566678)
		(end 276.647656 -252.141736)
		(width 0.20066)
		(layer "F.Cu")
		(net "M_C_CPU0_SB_CA<0>")
	)
	(segment
		(start 272.502376 -252.566678)
		(end 271.168114 -252.566678)
		(width 0.20066)
		(layer "F.Cu")
		(net "M_C_CPU0_SB_CA<0>")
	)
	(segment
		(start 276.647656 -252.141736)
		(end 276.469094 -252.141736)
		(width 0.20066)
		(layer "F.Cu")
		(net "M_C_CPU0_SB_CA<0>")
	)
	(segment
		(start 273.218148 -252.778006)
		(end 272.713704 -252.778006)
		(width 0.20066)
		(layer "F.Cu")
		(net "M_C_CPU0_SB_CA<0>")
	)
	(segment
		(start 273.37258 -252.295406)
		(end 273.37258 -252.623574)
		(width 0.20066)
		(layer "F.Cu")
		(net "M_C_CPU0_SB_CA<0>")
	)
	(segment
		(start 274.152868 -252.141736)
		(end 274.143978 -252.132846)
		(width 0.1016)
		(layer "F.Cu")
		(net "M_C_CPU0_SB_CA<0>")
	)
	(segment
		(start 273.37258 -252.623574)
		(end 273.218148 -252.778006)
		(width 0.20066)
		(layer "F.Cu")
		(net "M_C_CPU0_SB_CA<0>")
	)
	(segment
		(start 276.138386 -252.141736)
		(end 274.152868 -252.141736)
		(width 0.1016)
		(layer "F.Cu")
		(net "M_C_CPU0_SB_CA<0>")
	)
	(segment
		(start 272.713704 -252.778006)
		(end 272.502376 -252.566678)
		(width 0.20066)
		(layer "F.Cu")
		(net "M_C_CPU0_SB_CA<0>")
	)
	(segment
		(start 278.711914 -252.566678)
		(end 277.072598 -252.566678)
		(width 0.20066)
		(layer "F.Cu")
		(net "M_C_CPU0_SB_CA<0>")
	)
	(segment
		(start 279.816814 -252.566678)
		(end 278.711914 -252.566678)
		(width 0.20066)
		(layer "F.Cu")
		(net "M_C_CPU0_SB_CA<0>")
	)
	(segment
		(start 276.469094 -252.141736)
		(end 276.138386 -252.141736)
		(width 0.101854)
		(layer "F.Cu")
		(net "M_C_CPU0_SB_CA<0>")
	)
	(segment
		(start 273.53514 -252.132846)
		(end 273.37258 -252.295406)
		(width 0.20066)
		(layer "F.Cu")
		(net "M_C_CPU0_SB_CA<0>")
	)
	(segment
		(start 341.364316 -254.197612)
		(end 342.303862 -254.733552)
		(width 0.20066)
		(layer "F.Cu")
		(net "M_C_CPU0_SB_CA<0>")
	)
	(segment
		(start 342.399366 -253.621032)
		(end 342.654128 -253.36627)
		(width 0.088646)
		(layer "In4.Cu")
		(net "M_C_CPU0_SB_CA<0>")
	)
	(segment
		(start 342.303862 -254.733552)
		(end 342.147398 -254.462534)
		(width 0.088646)
		(layer "In4.Cu")
		(net "M_C_CPU0_SB_CA<0>")
	)
	(segment
		(start 281.196288 -252.566678)
		(end 279.816814 -252.566678)
		(width 0.18288)
		(layer "In4.Cu")
		(net "M_C_CPU0_SB_CA<0>")
	)
	(segment
		(start 342.654128 -251.69876)
		(end 341.323168 -250.3678)
		(width 0.18288)
		(layer "In4.Cu")
		(net "M_C_CPU0_SB_CA<0>")
	)
	(segment
		(start 333.830168 -250.3678)
		(end 333.377794 -249.915426)
		(width 0.18288)
		(layer "In4.Cu")
		(net "M_C_CPU0_SB_CA<0>")
	)
	(segment
		(start 342.654128 -253.035562)
		(end 342.654128 -251.69876)
		(width 0.18288)
		(layer "In4.Cu")
		(net "M_C_CPU0_SB_CA<0>")
	)
	(segment
		(start 282.92298 -251.851414)
		(end 281.196288 -252.566678)
		(width 0.18288)
		(layer "In4.Cu")
		(net "M_C_CPU0_SB_CA<0>")
	)
	(segment
		(start 342.399366 -253.919736)
		(end 342.399366 -253.621032)
		(width 0.088646)
		(layer "In4.Cu")
		(net "M_C_CPU0_SB_CA<0>")
	)
	(segment
		(start 284.682184 -251.85243)
		(end 284.682184 -251.636784)
		(width 0.18288)
		(layer "In4.Cu")
		(net "M_C_CPU0_SB_CA<0>")
	)
	(segment
		(start 329.456542 -250.21159)
		(end 328.145902 -248.90095)
		(width 0.18288)
		(layer "In4.Cu")
		(net "M_C_CPU0_SB_CA<0>")
	)
	(segment
		(start 324.406768 -248.90095)
		(end 321.165982 -252.141736)
		(width 0.18288)
		(layer "In4.Cu")
		(net "M_C_CPU0_SB_CA<0>")
	)
	(segment
		(start 332.678786 -250.21159)
		(end 329.456542 -250.21159)
		(width 0.18288)
		(layer "In4.Cu")
		(net "M_C_CPU0_SB_CA<0>")
	)
	(segment
		(start 284.97149 -252.141736)
		(end 284.682184 -251.85243)
		(width 0.18288)
		(layer "In4.Cu")
		(net "M_C_CPU0_SB_CA<0>")
	)
	(segment
		(start 321.165982 -252.141736)
		(end 284.97149 -252.141736)
		(width 0.18288)
		(layer "In4.Cu")
		(net "M_C_CPU0_SB_CA<0>")
	)
	(segment
		(start 284.337252 -251.291852)
		(end 283.482542 -251.291852)
		(width 0.18288)
		(layer "In4.Cu")
		(net "M_C_CPU0_SB_CA<0>")
	)
	(segment
		(start 333.377794 -249.915426)
		(end 332.97495 -249.915426)
		(width 0.18288)
		(layer "In4.Cu")
		(net "M_C_CPU0_SB_CA<0>")
	)
	(segment
		(start 284.682184 -251.636784)
		(end 284.337252 -251.291852)
		(width 0.18288)
		(layer "In4.Cu")
		(net "M_C_CPU0_SB_CA<0>")
	)
	(segment
		(start 328.145902 -248.90095)
		(end 324.406768 -248.90095)
		(width 0.18288)
		(layer "In4.Cu")
		(net "M_C_CPU0_SB_CA<0>")
	)
	(segment
		(start 342.147398 -254.462534)
		(end 342.171528 -254.37338)
		(width 0.088646)
		(layer "In4.Cu")
		(net "M_C_CPU0_SB_CA<0>")
	)
	(segment
		(start 332.97495 -249.915426)
		(end 332.678786 -250.21159)
		(width 0.18288)
		(layer "In4.Cu")
		(net "M_C_CPU0_SB_CA<0>")
	)
	(segment
		(start 341.323168 -250.3678)
		(end 333.830168 -250.3678)
		(width 0.18288)
		(layer "In4.Cu")
		(net "M_C_CPU0_SB_CA<0>")
	)
	(segment
		(start 342.654128 -253.36627)
		(end 342.654128 -253.035562)
		(width 0.088646)
		(layer "In4.Cu")
		(net "M_C_CPU0_SB_CA<0>")
	)
	(segment
		(start 283.482542 -251.291852)
		(end 282.92298 -251.851414)
		(width 0.18288)
		(layer "In4.Cu")
		(net "M_C_CPU0_SB_CA<0>")
	)
	(arc
		(start 342.171528 -254.37338)
		(mid 342.339227 -254.173575)
		(end 342.399366 -253.919736)
		(width 0.088646)
		(layer "In4.Cu")
		(net "M_C_CPU0_SB_CA<0>")
	)
	(segment
		(start 343.713562 -253.919482)
		(end 343.713816 -253.919736)
		(width 0.20066)
		(layer "F.Cu")
		(net "M_C_CPU0_SA_RSP<1>")
	)
	(segment
		(start 343.713562 -253.383796)
		(end 343.713562 -253.919482)
		(width 0.20066)
		(layer "F.Cu")
		(net "M_C_CPU0_SA_RSP<1>")
	)
	(segment
		(start 279.816814 -244.066568)
		(end 278.711914 -244.066568)
		(width 0.20066)
		(layer "F.Cu")
		(net "M_C_CPU0_SA_RSP<1>")
	)
	(segment
		(start 290.365434 -249.346974)
		(end 290.040314 -249.346974)
		(width 0.18288)
		(layer "In6.Cu")
		(net "M_C_CPU0_SA_RSP<1>")
	)
	(segment
		(start 287.452054 -247.73128)
		(end 286.474916 -247.73128)
		(width 0.18288)
		(layer "In6.Cu")
		(net "M_C_CPU0_SA_RSP<1>")
	)
	(segment
		(start 286.474916 -247.73128)
		(end 285.863792 -247.120156)
		(width 0.18288)
		(layer "In6.Cu")
		(net "M_C_CPU0_SA_RSP<1>")
	)
	(segment
		(start 292.279832 -248.793)
		(end 292.13302 -248.646188)
		(width 0.18288)
		(layer "In6.Cu")
		(net "M_C_CPU0_SA_RSP<1>")
	)
	(segment
		(start 283.08173 -246.396002)
		(end 282.89885 -246.578882)
		(width 0.18288)
		(layer "In6.Cu")
		(net "M_C_CPU0_SA_RSP<1>")
	)
	(segment
		(start 326.522842 -254.57785)
		(end 324.442582 -254.57785)
		(width 0.18288)
		(layer "In6.Cu")
		(net "M_C_CPU0_SA_RSP<1>")
	)
	(segment
		(start 290.040314 -249.346974)
		(end 289.857434 -249.164094)
		(width 0.18288)
		(layer "In6.Cu")
		(net "M_C_CPU0_SA_RSP<1>")
	)
	(segment
		(start 339.297518 -254.409194)
		(end 339.287104 -254.41529)
		(width 0.088646)
		(layer "In6.Cu")
		(net "M_C_CPU0_SA_RSP<1>")
	)
	(segment
		(start 340.237064 -254.409194)
		(end 340.22665 -254.41529)
		(width 0.088646)
		(layer "In6.Cu")
		(net "M_C_CPU0_SA_RSP<1>")
	)
	(segment
		(start 297.360594 -250.652026)
		(end 295.449498 -248.74093)
		(width 0.18288)
		(layer "In6.Cu")
		(net "M_C_CPU0_SA_RSP<1>")
	)
	(segment
		(start 333.706978 -254.13589)
		(end 332.95463 -253.383034)
		(width 0.088646)
		(layer "In6.Cu")
		(net "M_C_CPU0_SA_RSP<1>")
	)
	(segment
		(start 299.722794 -252.079506)
		(end 299.722794 -251.68225)
		(width 0.18288)
		(layer "In6.Cu")
		(net "M_C_CPU0_SA_RSP<1>")
	)
	(segment
		(start 290.731194 -248.646188)
		(end 290.548314 -248.829068)
		(width 0.18288)
		(layer "In6.Cu")
		(net "M_C_CPU0_SA_RSP<1>")
	)
	(segment
		(start 297.360594 -250.979686)
		(end 297.360594 -250.652026)
		(width 0.18288)
		(layer "In6.Cu")
		(net "M_C_CPU0_SA_RSP<1>")
	)
	(segment
		(start 311.10301 -252.701298)
		(end 305.345846 -252.701298)
		(width 0.18288)
		(layer "In6.Cu")
		(net "M_C_CPU0_SA_RSP<1>")
	)
	(segment
		(start 303.634394 -252.076966)
		(end 303.306734 -252.404626)
		(width 0.18288)
		(layer "In6.Cu")
		(net "M_C_CPU0_SA_RSP<1>")
	)
	(segment
		(start 290.548314 -248.829068)
		(end 290.548314 -249.164094)
		(width 0.18288)
		(layer "In6.Cu")
		(net "M_C_CPU0_SA_RSP<1>")
	)
	(segment
		(start 342.399366 -253.9111)
		(end 342.399366 -253.919736)
		(width 0.088646)
		(layer "In6.Cu")
		(net "M_C_CPU0_SA_RSP<1>")
	)
	(segment
		(start 282.39085 -246.396002)
		(end 282.39085 -245.523512)
		(width 0.18288)
		(layer "In6.Cu")
		(net "M_C_CPU0_SA_RSP<1>")
	)
	(segment
		(start 289.857434 -249.164094)
		(end 289.857434 -248.829068)
		(width 0.18288)
		(layer "In6.Cu")
		(net "M_C_CPU0_SA_RSP<1>")
	)
	(segment
		(start 297.671998 -251.29109)
		(end 297.360594 -250.979686)
		(width 0.18288)
		(layer "In6.Cu")
		(net "M_C_CPU0_SA_RSP<1>")
	)
	(segment
		(start 294.828214 -248.74093)
		(end 294.827452 -248.741692)
		(width 0.18288)
		(layer "In6.Cu")
		(net "M_C_CPU0_SA_RSP<1>")
	)
	(segment
		(start 343.713816 -253.919736)
		(end 344.026744 -253.919736)
		(width 0.088646)
		(layer "In6.Cu")
		(net "M_C_CPU0_SA_RSP<1>")
	)
	(segment
		(start 282.57373 -246.578882)
		(end 282.39085 -246.396002)
		(width 0.18288)
		(layer "In6.Cu")
		(net "M_C_CPU0_SA_RSP<1>")
	)
	(segment
		(start 323.325744 -254.115062)
		(end 316.788292 -254.115062)
		(width 0.18288)
		(layer "In6.Cu")
		(net "M_C_CPU0_SA_RSP<1>")
	)
	(segment
		(start 294.827452 -248.741692)
		(end 294.162226 -248.741692)
		(width 0.18288)
		(layer "In6.Cu")
		(net "M_C_CPU0_SA_RSP<1>")
	)
	(segment
		(start 282.89885 -246.578882)
		(end 282.57373 -246.578882)
		(width 0.18288)
		(layer "In6.Cu")
		(net "M_C_CPU0_SA_RSP<1>")
	)
	(segment
		(start 294.110918 -248.793)
		(end 292.279832 -248.793)
		(width 0.18288)
		(layer "In6.Cu")
		(net "M_C_CPU0_SA_RSP<1>")
	)
	(segment
		(start 300.047914 -252.404626)
		(end 299.722794 -252.079506)
		(width 0.18288)
		(layer "In6.Cu")
		(net "M_C_CPU0_SA_RSP<1>")
	)
	(segment
		(start 342.975692 -253.604014)
		(end 342.96096 -253.595378)
		(width 0.088646)
		(layer "In6.Cu")
		(net "M_C_CPU0_SA_RSP<1>")
	)
	(segment
		(start 285.863792 -247.120156)
		(end 285.863792 -246.004334)
		(width 0.18288)
		(layer "In6.Cu")
		(net "M_C_CPU0_SA_RSP<1>")
	)
	(segment
		(start 312.397394 -252.296676)
		(end 312.066178 -251.964698)
		(width 0.18288)
		(layer "In6.Cu")
		(net "M_C_CPU0_SA_RSP<1>")
	)
	(segment
		(start 343.913206 -253.60249)
		(end 343.90076 -253.595378)
		(width 0.088646)
		(layer "In6.Cu")
		(net "M_C_CPU0_SA_RSP<1>")
	)
	(segment
		(start 289.857434 -248.829068)
		(end 289.674554 -248.646188)
		(width 0.18288)
		(layer "In6.Cu")
		(net "M_C_CPU0_SA_RSP<1>")
	)
	(segment
		(start 341.176864 -254.409194)
		(end 341.162132 -254.41783)
		(width 0.088646)
		(layer "In6.Cu")
		(net "M_C_CPU0_SA_RSP<1>")
	)
	(segment
		(start 311.83961 -251.964698)
		(end 311.10301 -252.701298)
		(width 0.18288)
		(layer "In6.Cu")
		(net "M_C_CPU0_SA_RSP<1>")
	)
	(segment
		(start 285.863792 -246.004334)
		(end 285.20009 -245.340632)
		(width 0.18288)
		(layer "In6.Cu")
		(net "M_C_CPU0_SA_RSP<1>")
	)
	(segment
		(start 304.721514 -252.076966)
		(end 303.634394 -252.076966)
		(width 0.18288)
		(layer "In6.Cu")
		(net "M_C_CPU0_SA_RSP<1>")
	)
	(segment
		(start 305.345846 -252.701298)
		(end 304.721514 -252.076966)
		(width 0.18288)
		(layer "In6.Cu")
		(net "M_C_CPU0_SA_RSP<1>")
	)
	(segment
		(start 329.40752 -253.383034)
		(end 326.522842 -254.57785)
		(width 0.18288)
		(layer "In6.Cu")
		(net "M_C_CPU0_SA_RSP<1>")
	)
	(segment
		(start 299.331634 -251.29109)
		(end 297.671998 -251.29109)
		(width 0.18288)
		(layer "In6.Cu")
		(net "M_C_CPU0_SA_RSP<1>")
	)
	(segment
		(start 285.20009 -245.340632)
		(end 283.26461 -245.340632)
		(width 0.18288)
		(layer "In6.Cu")
		(net "M_C_CPU0_SA_RSP<1>")
	)
	(segment
		(start 294.162226 -248.741692)
		(end 294.110918 -248.793)
		(width 0.18288)
		(layer "In6.Cu")
		(net "M_C_CPU0_SA_RSP<1>")
	)
	(segment
		(start 281.090878 -245.340632)
		(end 279.816814 -244.066568)
		(width 0.18288)
		(layer "In6.Cu")
		(net "M_C_CPU0_SA_RSP<1>")
	)
	(segment
		(start 324.229984 -254.489712)
		(end 323.325744 -254.115062)
		(width 0.18288)
		(layer "In6.Cu")
		(net "M_C_CPU0_SA_RSP<1>")
	)
	(segment
		(start 290.548314 -249.164094)
		(end 290.365434 -249.346974)
		(width 0.18288)
		(layer "In6.Cu")
		(net "M_C_CPU0_SA_RSP<1>")
	)
	(segment
		(start 299.722794 -251.68225)
		(end 299.331634 -251.29109)
		(width 0.18288)
		(layer "In6.Cu")
		(net "M_C_CPU0_SA_RSP<1>")
	)
	(segment
		(start 303.306734 -252.404626)
		(end 300.047914 -252.404626)
		(width 0.18288)
		(layer "In6.Cu")
		(net "M_C_CPU0_SA_RSP<1>")
	)
	(segment
		(start 344.026744 -253.919736)
		(end 344.083894 -253.862586)
		(width 0.088646)
		(layer "In6.Cu")
		(net "M_C_CPU0_SA_RSP<1>")
	)
	(segment
		(start 332.375002 -253.383034)
		(end 329.40752 -253.383034)
		(width 0.18288)
		(layer "In6.Cu")
		(net "M_C_CPU0_SA_RSP<1>")
	)
	(segment
		(start 288.366962 -248.646188)
		(end 287.452054 -247.73128)
		(width 0.18288)
		(layer "In6.Cu")
		(net "M_C_CPU0_SA_RSP<1>")
	)
	(segment
		(start 312.066178 -251.964698)
		(end 311.83961 -251.964698)
		(width 0.18288)
		(layer "In6.Cu")
		(net "M_C_CPU0_SA_RSP<1>")
	)
	(segment
		(start 343.90076 -253.595378)
		(end 343.888822 -253.58852)
		(width 0.088646)
		(layer "In6.Cu")
		(net "M_C_CPU0_SA_RSP<1>")
	)
	(segment
		(start 316.788292 -254.115062)
		(end 312.397394 -252.296676)
		(width 0.18288)
		(layer "In6.Cu")
		(net "M_C_CPU0_SA_RSP<1>")
	)
	(segment
		(start 295.449498 -248.74093)
		(end 294.828214 -248.74093)
		(width 0.18288)
		(layer "In6.Cu")
		(net "M_C_CPU0_SA_RSP<1>")
	)
	(segment
		(start 324.230238 -254.489712)
		(end 324.229984 -254.489712)
		(width 0.18288)
		(layer "In6.Cu")
		(net "M_C_CPU0_SA_RSP<1>")
	)
	(segment
		(start 324.442582 -254.57785)
		(end 324.230238 -254.489712)
		(width 0.18288)
		(layer "In6.Cu")
		(net "M_C_CPU0_SA_RSP<1>")
	)
	(segment
		(start 342.116664 -254.409194)
		(end 342.101932 -254.41783)
		(width 0.088646)
		(layer "In6.Cu")
		(net "M_C_CPU0_SA_RSP<1>")
	)
	(segment
		(start 282.39085 -245.523512)
		(end 282.20797 -245.340632)
		(width 0.18288)
		(layer "In6.Cu")
		(net "M_C_CPU0_SA_RSP<1>")
	)
	(segment
		(start 289.674554 -248.646188)
		(end 288.366962 -248.646188)
		(width 0.18288)
		(layer "In6.Cu")
		(net "M_C_CPU0_SA_RSP<1>")
	)
	(segment
		(start 283.26461 -245.340632)
		(end 283.08173 -245.523512)
		(width 0.18288)
		(layer "In6.Cu")
		(net "M_C_CPU0_SA_RSP<1>")
	)
	(segment
		(start 283.08173 -245.523512)
		(end 283.08173 -246.396002)
		(width 0.18288)
		(layer "In6.Cu")
		(net "M_C_CPU0_SA_RSP<1>")
	)
	(segment
		(start 292.13302 -248.646188)
		(end 290.731194 -248.646188)
		(width 0.18288)
		(layer "In6.Cu")
		(net "M_C_CPU0_SA_RSP<1>")
	)
	(segment
		(start 342.12276 -254.405638)
		(end 342.116664 -254.409194)
		(width 0.088646)
		(layer "In6.Cu")
		(net "M_C_CPU0_SA_RSP<1>")
	)
	(segment
		(start 332.95463 -253.383034)
		(end 332.375002 -253.383034)
		(width 0.088646)
		(layer "In6.Cu")
		(net "M_C_CPU0_SA_RSP<1>")
	)
	(segment
		(start 282.20797 -245.340632)
		(end 281.090878 -245.340632)
		(width 0.18288)
		(layer "In6.Cu")
		(net "M_C_CPU0_SA_RSP<1>")
	)
	(arc
		(start 333.968598 -254.366014)
		(mid 333.834072 -254.255176)
		(end 333.706978 -254.13589)
		(width 0.088646)
		(layer "In6.Cu")
		(net "M_C_CPU0_SA_RSP<1>")
	)
	(arc
		(start 334.598264 -254.409194)
		(mid 334.315562 -254.48497)
		(end 334.03286 -254.409194)
		(width 0.088646)
		(layer "In6.Cu")
		(net "M_C_CPU0_SA_RSP<1>")
	)
	(arc
		(start 337.79206 -254.409194)
		(mid 337.604862 -254.359051)
		(end 337.417664 -254.409194)
		(width 0.088646)
		(layer "In6.Cu")
		(net "M_C_CPU0_SA_RSP<1>")
	)
	(arc
		(start 336.477864 -254.409194)
		(mid 336.195162 -254.48497)
		(end 335.91246 -254.409194)
		(width 0.088646)
		(layer "In6.Cu")
		(net "M_C_CPU0_SA_RSP<1>")
	)
	(arc
		(start 339.287104 -254.41529)
		(mid 339.008672 -254.485136)
		(end 338.73186 -254.409194)
		(width 0.088646)
		(layer "In6.Cu")
		(net "M_C_CPU0_SA_RSP<1>")
	)
	(arc
		(start 337.417664 -254.409194)
		(mid 337.134962 -254.48497)
		(end 336.85226 -254.409194)
		(width 0.088646)
		(layer "In6.Cu")
		(net "M_C_CPU0_SA_RSP<1>")
	)
	(arc
		(start 335.538064 -254.409194)
		(mid 335.255362 -254.48497)
		(end 334.97266 -254.409194)
		(width 0.088646)
		(layer "In6.Cu")
		(net "M_C_CPU0_SA_RSP<1>")
	)
	(arc
		(start 340.61146 -254.409194)
		(mid 340.424262 -254.359051)
		(end 340.237064 -254.409194)
		(width 0.088646)
		(layer "In6.Cu")
		(net "M_C_CPU0_SA_RSP<1>")
	)
	(arc
		(start 339.671914 -254.409194)
		(mid 339.484716 -254.359051)
		(end 339.297518 -254.409194)
		(width 0.088646)
		(layer "In6.Cu")
		(net "M_C_CPU0_SA_RSP<1>")
	)
	(arc
		(start 343.526364 -253.595378)
		(mid 343.252165 -253.671213)
		(end 342.975692 -253.604014)
		(width 0.088646)
		(layer "In6.Cu")
		(net "M_C_CPU0_SA_RSP<1>")
	)
	(arc
		(start 344.083894 -253.862586)
		(mid 344.026843 -253.713963)
		(end 343.913206 -253.60249)
		(width 0.088646)
		(layer "In6.Cu")
		(net "M_C_CPU0_SA_RSP<1>")
	)
	(arc
		(start 335.91246 -254.409194)
		(mid 335.725262 -254.359051)
		(end 335.538064 -254.409194)
		(width 0.088646)
		(layer "In6.Cu")
		(net "M_C_CPU0_SA_RSP<1>")
	)
	(arc
		(start 342.96096 -253.595378)
		(mid 342.773762 -253.545235)
		(end 342.586564 -253.595378)
		(width 0.088646)
		(layer "In6.Cu")
		(net "M_C_CPU0_SA_RSP<1>")
	)
	(arc
		(start 343.888822 -253.58852)
		(mid 343.706711 -253.545195)
		(end 343.526364 -253.595378)
		(width 0.088646)
		(layer "In6.Cu")
		(net "M_C_CPU0_SA_RSP<1>")
	)
	(arc
		(start 340.22665 -254.41529)
		(mid 339.948472 -254.485013)
		(end 339.671914 -254.409194)
		(width 0.088646)
		(layer "In6.Cu")
		(net "M_C_CPU0_SA_RSP<1>")
	)
	(arc
		(start 342.101932 -254.41783)
		(mid 341.825457 -254.48515)
		(end 341.55126 -254.409194)
		(width 0.088646)
		(layer "In6.Cu")
		(net "M_C_CPU0_SA_RSP<1>")
	)
	(arc
		(start 338.73186 -254.409194)
		(mid 338.544662 -254.359051)
		(end 338.357464 -254.409194)
		(width 0.088646)
		(layer "In6.Cu")
		(net "M_C_CPU0_SA_RSP<1>")
	)
	(arc
		(start 336.85226 -254.409194)
		(mid 336.665062 -254.359051)
		(end 336.477864 -254.409194)
		(width 0.088646)
		(layer "In6.Cu")
		(net "M_C_CPU0_SA_RSP<1>")
	)
	(arc
		(start 334.97266 -254.409194)
		(mid 334.785462 -254.359051)
		(end 334.598264 -254.409194)
		(width 0.088646)
		(layer "In6.Cu")
		(net "M_C_CPU0_SA_RSP<1>")
	)
	(arc
		(start 342.399366 -253.919736)
		(mid 342.325375 -254.199302)
		(end 342.12276 -254.405638)
		(width 0.088646)
		(layer "In6.Cu")
		(net "M_C_CPU0_SA_RSP<1>")
	)
	(arc
		(start 334.03286 -254.409194)
		(mid 333.99999 -254.388704)
		(end 333.968598 -254.366014)
		(width 0.088646)
		(layer "In6.Cu")
		(net "M_C_CPU0_SA_RSP<1>")
	)
	(arc
		(start 342.586564 -253.595378)
		(mid 342.451631 -253.728732)
		(end 342.399366 -253.9111)
		(width 0.088646)
		(layer "In6.Cu")
		(net "M_C_CPU0_SA_RSP<1>")
	)
	(arc
		(start 341.162132 -254.41783)
		(mid 340.885657 -254.48515)
		(end 340.61146 -254.409194)
		(width 0.088646)
		(layer "In6.Cu")
		(net "M_C_CPU0_SA_RSP<1>")
	)
	(arc
		(start 341.55126 -254.409194)
		(mid 341.364062 -254.359051)
		(end 341.176864 -254.409194)
		(width 0.088646)
		(layer "In6.Cu")
		(net "M_C_CPU0_SA_RSP<1>")
	)
	(arc
		(start 338.357464 -254.409194)
		(mid 338.074762 -254.48497)
		(end 337.79206 -254.409194)
		(width 0.088646)
		(layer "In6.Cu")
		(net "M_C_CPU0_SA_RSP<1>")
	)
	(segment
		(start 272.273014 -244.066568)
		(end 271.168114 -244.066568)
		(width 0.20066)
		(layer "F.Cu")
		(net "M_C_CPU0_SA_RSP<0>")
	)
	(segment
		(start 343.243916 -254.733298)
		(end 343.243662 -254.733552)
		(width 0.20066)
		(layer "F.Cu")
		(net "M_C_CPU0_SA_RSP<0>")
	)
	(segment
		(start 343.243916 -254.197612)
		(end 343.243916 -254.733298)
		(width 0.20066)
		(layer "F.Cu")
		(net "M_C_CPU0_SA_RSP<0>")
	)
	(segment
		(start 297.99661 -253.506986)
		(end 296.383964 -252.870716)
		(width 0.18288)
		(layer "In6.Cu")
		(net "M_C_CPU0_SA_RSP<0>")
	)
	(segment
		(start 339.767164 -255.223264)
		(end 339.75675 -255.22936)
		(width 0.088646)
		(layer "In6.Cu")
		(net "M_C_CPU0_SA_RSP<0>")
	)
	(segment
		(start 337.332828 -255.22936)
		(end 337.322414 -255.223264)
		(width 0.088646)
		(layer "In6.Cu")
		(net "M_C_CPU0_SA_RSP<0>")
	)
	(segment
		(start 288.346896 -250.439682)
		(end 288.020506 -250.766072)
		(width 0.18288)
		(layer "In6.Cu")
		(net "M_C_CPU0_SA_RSP<0>")
	)
	(segment
		(start 290.05276 -251.01677)
		(end 290.05276 -250.622562)
		(width 0.18288)
		(layer "In6.Cu")
		(net "M_C_CPU0_SA_RSP<0>")
	)
	(segment
		(start 342.036146 -255.2319)
		(end 342.021414 -255.223264)
		(width 0.088646)
		(layer "In6.Cu")
		(net "M_C_CPU0_SA_RSP<0>")
	)
	(segment
		(start 295.674034 -251.505466)
		(end 295.460674 -251.292106)
		(width 0.18288)
		(layer "In6.Cu")
		(net "M_C_CPU0_SA_RSP<0>")
	)
	(segment
		(start 295.036494 -251.290836)
		(end 294.120824 -251.290836)
		(width 0.18288)
		(layer "In6.Cu")
		(net "M_C_CPU0_SA_RSP<0>")
	)
	(segment
		(start 294.120824 -251.290836)
		(end 293.26967 -250.439682)
		(width 0.18288)
		(layer "In6.Cu")
		(net "M_C_CPU0_SA_RSP<0>")
	)
	(segment
		(start 274.28825 -246.791226)
		(end 273.357594 -245.86057)
		(width 0.18288)
		(layer "In6.Cu")
		(net "M_C_CPU0_SA_RSP<0>")
	)
	(segment
		(start 290.23564 -251.19965)
		(end 290.05276 -251.01677)
		(width 0.18288)
		(layer "In6.Cu")
		(net "M_C_CPU0_SA_RSP<0>")
	)
	(segment
		(start 295.460674 -251.292106)
		(end 295.037764 -251.292106)
		(width 0.18288)
		(layer "In6.Cu")
		(net "M_C_CPU0_SA_RSP<0>")
	)
	(segment
		(start 290.74364 -251.01677)
		(end 290.56076 -251.19965)
		(width 0.18288)
		(layer "In6.Cu")
		(net "M_C_CPU0_SA_RSP<0>")
	)
	(segment
		(start 338.272374 -255.22936)
		(end 338.26196 -255.223264)
		(width 0.088646)
		(layer "In6.Cu")
		(net "M_C_CPU0_SA_RSP<0>")
	)
	(segment
		(start 293.26967 -250.439682)
		(end 290.92652 -250.439682)
		(width 0.18288)
		(layer "In6.Cu")
		(net "M_C_CPU0_SA_RSP<0>")
	)
	(segment
		(start 277.88616 -247.890792)
		(end 276.786594 -246.791226)
		(width 0.18288)
		(layer "In6.Cu")
		(net "M_C_CPU0_SA_RSP<0>")
	)
	(segment
		(start 340.151974 -255.22936)
		(end 340.14156 -255.223264)
		(width 0.088646)
		(layer "In6.Cu")
		(net "M_C_CPU0_SA_RSP<0>")
	)
	(segment
		(start 343.243662 -254.733552)
		(end 342.616028 -255.206246)
		(width 0.088646)
		(layer "In6.Cu")
		(net "M_C_CPU0_SA_RSP<0>")
	)
	(segment
		(start 333.445866 -255.133348)
		(end 332.700122 -254.387604)
		(width 0.088646)
		(layer "In6.Cu")
		(net "M_C_CPU0_SA_RSP<0>")
	)
	(segment
		(start 328.81316 -254.387604)
		(end 326.639174 -255.288034)
		(width 0.18288)
		(layer "In6.Cu")
		(net "M_C_CPU0_SA_RSP<0>")
	)
	(segment
		(start 299.777912 -255.288288)
		(end 297.99661 -253.506986)
		(width 0.18288)
		(layer "In6.Cu")
		(net "M_C_CPU0_SA_RSP<0>")
	)
	(segment
		(start 273.357594 -245.86057)
		(end 273.357594 -245.151148)
		(width 0.18288)
		(layer "In6.Cu")
		(net "M_C_CPU0_SA_RSP<0>")
	)
	(segment
		(start 280.36393 -247.890792)
		(end 277.88616 -247.890792)
		(width 0.18288)
		(layer "In6.Cu")
		(net "M_C_CPU0_SA_RSP<0>")
	)
	(segment
		(start 342.586564 -255.22301)
		(end 342.586818 -255.223264)
		(width 0.088646)
		(layer "In6.Cu")
		(net "M_C_CPU0_SA_RSP<0>")
	)
	(segment
		(start 314.41517 -255.288288)
		(end 299.777912 -255.288288)
		(width 0.18288)
		(layer "In6.Cu")
		(net "M_C_CPU0_SA_RSP<0>")
	)
	(segment
		(start 314.415424 -255.288034)
		(end 314.41517 -255.288288)
		(width 0.18288)
		(layer "In6.Cu")
		(net "M_C_CPU0_SA_RSP<0>")
	)
	(segment
		(start 332.375002 -254.387604)
		(end 328.81316 -254.387604)
		(width 0.18288)
		(layer "In6.Cu")
		(net "M_C_CPU0_SA_RSP<0>")
	)
	(segment
		(start 273.357594 -245.151148)
		(end 272.273014 -244.066568)
		(width 0.18288)
		(layer "In6.Cu")
		(net "M_C_CPU0_SA_RSP<0>")
	)
	(segment
		(start 276.786594 -246.791226)
		(end 274.28825 -246.791226)
		(width 0.18288)
		(layer "In6.Cu")
		(net "M_C_CPU0_SA_RSP<0>")
	)
	(segment
		(start 281.214068 -248.74093)
		(end 280.36393 -247.890792)
		(width 0.18288)
		(layer "In6.Cu")
		(net "M_C_CPU0_SA_RSP<0>")
	)
	(segment
		(start 342.616028 -255.206246)
		(end 342.586564 -255.22301)
		(width 0.088646)
		(layer "In6.Cu")
		(net "M_C_CPU0_SA_RSP<0>")
	)
	(segment
		(start 326.639174 -255.288034)
		(end 314.415424 -255.288034)
		(width 0.18288)
		(layer "In6.Cu")
		(net "M_C_CPU0_SA_RSP<0>")
	)
	(segment
		(start 290.56076 -251.19965)
		(end 290.23564 -251.19965)
		(width 0.18288)
		(layer "In6.Cu")
		(net "M_C_CPU0_SA_RSP<0>")
	)
	(segment
		(start 296.383964 -252.870716)
		(end 295.674034 -252.160786)
		(width 0.18288)
		(layer "In6.Cu")
		(net "M_C_CPU0_SA_RSP<0>")
	)
	(segment
		(start 295.674034 -252.160786)
		(end 295.674034 -251.505466)
		(width 0.18288)
		(layer "In6.Cu")
		(net "M_C_CPU0_SA_RSP<0>")
	)
	(segment
		(start 341.096346 -255.2319)
		(end 341.081614 -255.223264)
		(width 0.088646)
		(layer "In6.Cu")
		(net "M_C_CPU0_SA_RSP<0>")
	)
	(segment
		(start 286.634936 -250.766072)
		(end 284.609794 -248.74093)
		(width 0.18288)
		(layer "In6.Cu")
		(net "M_C_CPU0_SA_RSP<0>")
	)
	(segment
		(start 290.05276 -250.622562)
		(end 289.86988 -250.439682)
		(width 0.18288)
		(layer "In6.Cu")
		(net "M_C_CPU0_SA_RSP<0>")
	)
	(segment
		(start 290.74364 -250.622562)
		(end 290.74364 -251.01677)
		(width 0.18288)
		(layer "In6.Cu")
		(net "M_C_CPU0_SA_RSP<0>")
	)
	(segment
		(start 332.700122 -254.387604)
		(end 332.375002 -254.387604)
		(width 0.088646)
		(layer "In6.Cu")
		(net "M_C_CPU0_SA_RSP<0>")
	)
	(segment
		(start 288.020506 -250.766072)
		(end 286.634936 -250.766072)
		(width 0.18288)
		(layer "In6.Cu")
		(net "M_C_CPU0_SA_RSP<0>")
	)
	(segment
		(start 295.037764 -251.292106)
		(end 295.036494 -251.290836)
		(width 0.18288)
		(layer "In6.Cu")
		(net "M_C_CPU0_SA_RSP<0>")
	)
	(segment
		(start 289.86988 -250.439682)
		(end 288.346896 -250.439682)
		(width 0.18288)
		(layer "In6.Cu")
		(net "M_C_CPU0_SA_RSP<0>")
	)
	(segment
		(start 336.392774 -255.22936)
		(end 336.38236 -255.223264)
		(width 0.088646)
		(layer "In6.Cu")
		(net "M_C_CPU0_SA_RSP<0>")
	)
	(segment
		(start 290.92652 -250.439682)
		(end 290.74364 -250.622562)
		(width 0.18288)
		(layer "In6.Cu")
		(net "M_C_CPU0_SA_RSP<0>")
	)
	(segment
		(start 284.609794 -248.74093)
		(end 281.214068 -248.74093)
		(width 0.18288)
		(layer "In6.Cu")
		(net "M_C_CPU0_SA_RSP<0>")
	)
	(arc
		(start 340.14156 -255.223264)
		(mid 339.954362 -255.173121)
		(end 339.767164 -255.223264)
		(width 0.088646)
		(layer "In6.Cu")
		(net "M_C_CPU0_SA_RSP<0>")
	)
	(arc
		(start 338.26196 -255.223264)
		(mid 338.074762 -255.173121)
		(end 337.887564 -255.223264)
		(width 0.088646)
		(layer "In6.Cu")
		(net "M_C_CPU0_SA_RSP<0>")
	)
	(arc
		(start 334.50276 -255.223264)
		(mid 334.315562 -255.173121)
		(end 334.128364 -255.223264)
		(width 0.088646)
		(layer "In6.Cu")
		(net "M_C_CPU0_SA_RSP<0>")
	)
	(arc
		(start 337.887564 -255.223264)
		(mid 337.611005 -255.298973)
		(end 337.332828 -255.22936)
		(width 0.088646)
		(layer "In6.Cu")
		(net "M_C_CPU0_SA_RSP<0>")
	)
	(arc
		(start 334.128364 -255.223264)
		(mid 333.771841 -255.294167)
		(end 333.445866 -255.133348)
		(width 0.088646)
		(layer "In6.Cu")
		(net "M_C_CPU0_SA_RSP<0>")
	)
	(arc
		(start 342.021414 -255.223264)
		(mid 341.834216 -255.173121)
		(end 341.647018 -255.223264)
		(width 0.088646)
		(layer "In6.Cu")
		(net "M_C_CPU0_SA_RSP<0>")
	)
	(arc
		(start 336.948018 -255.223264)
		(mid 336.671205 -255.2991)
		(end 336.392774 -255.22936)
		(width 0.088646)
		(layer "In6.Cu")
		(net "M_C_CPU0_SA_RSP<0>")
	)
	(arc
		(start 339.75675 -255.22936)
		(mid 339.478572 -255.299052)
		(end 339.202014 -255.223264)
		(width 0.088646)
		(layer "In6.Cu")
		(net "M_C_CPU0_SA_RSP<0>")
	)
	(arc
		(start 337.322414 -255.223264)
		(mid 337.135216 -255.173121)
		(end 336.948018 -255.223264)
		(width 0.088646)
		(layer "In6.Cu")
		(net "M_C_CPU0_SA_RSP<0>")
	)
	(arc
		(start 336.38236 -255.223264)
		(mid 336.195162 -255.173121)
		(end 336.007964 -255.223264)
		(width 0.088646)
		(layer "In6.Cu")
		(net "M_C_CPU0_SA_RSP<0>")
	)
	(arc
		(start 338.827618 -255.223264)
		(mid 338.550805 -255.2991)
		(end 338.272374 -255.22936)
		(width 0.088646)
		(layer "In6.Cu")
		(net "M_C_CPU0_SA_RSP<0>")
	)
	(arc
		(start 335.44256 -255.223264)
		(mid 335.255362 -255.173121)
		(end 335.068164 -255.223264)
		(width 0.088646)
		(layer "In6.Cu")
		(net "M_C_CPU0_SA_RSP<0>")
	)
	(arc
		(start 341.081614 -255.223264)
		(mid 340.894416 -255.173121)
		(end 340.707218 -255.223264)
		(width 0.088646)
		(layer "In6.Cu")
		(net "M_C_CPU0_SA_RSP<0>")
	)
	(arc
		(start 341.647018 -255.223264)
		(mid 341.372789 -255.299189)
		(end 341.096346 -255.2319)
		(width 0.088646)
		(layer "In6.Cu")
		(net "M_C_CPU0_SA_RSP<0>")
	)
	(arc
		(start 342.586818 -255.223264)
		(mid 342.312589 -255.299189)
		(end 342.036146 -255.2319)
		(width 0.088646)
		(layer "In6.Cu")
		(net "M_C_CPU0_SA_RSP<0>")
	)
	(arc
		(start 336.007964 -255.223264)
		(mid 335.725262 -255.299006)
		(end 335.44256 -255.223264)
		(width 0.088646)
		(layer "In6.Cu")
		(net "M_C_CPU0_SA_RSP<0>")
	)
	(arc
		(start 335.068164 -255.223264)
		(mid 334.785462 -255.299006)
		(end 334.50276 -255.223264)
		(width 0.088646)
		(layer "In6.Cu")
		(net "M_C_CPU0_SA_RSP<0>")
	)
	(arc
		(start 339.202014 -255.223264)
		(mid 339.014816 -255.173121)
		(end 338.827618 -255.223264)
		(width 0.088646)
		(layer "In6.Cu")
		(net "M_C_CPU0_SA_RSP<0>")
	)
	(arc
		(start 340.707218 -255.223264)
		(mid 340.430405 -255.2991)
		(end 340.151974 -255.22936)
		(width 0.088646)
		(layer "In6.Cu")
		(net "M_C_CPU0_SA_RSP<0>")
	)
	(segment
		(start 339.954616 -253.38405)
		(end 339.954616 -253.919736)
		(width 0.20066)
		(layer "F.Cu")
		(net "M_C_CPU0_SA_PAR")
	)
	(segment
		(start 274.143978 -258.95554)
		(end 273.513042 -258.95554)
		(width 0.20066)
		(layer "F.Cu")
		(net "M_C_CPU0_SA_PAR")
	)
	(segment
		(start 274.16633 -258.941824)
		(end 274.152614 -258.95554)
		(width 0.101854)
		(layer "F.Cu")
		(net "M_C_CPU0_SA_PAR")
	)
	(segment
		(start 273.37258 -259.384546)
		(end 273.151346 -259.60578)
		(width 0.20066)
		(layer "F.Cu")
		(net "M_C_CPU0_SA_PAR")
	)
	(segment
		(start 273.37258 -259.095494)
		(end 273.37258 -259.384546)
		(width 0.20066)
		(layer "F.Cu")
		(net "M_C_CPU0_SA_PAR")
	)
	(segment
		(start 276.469094 -258.941824)
		(end 276.138386 -258.941824)
		(width 0.101854)
		(layer "F.Cu")
		(net "M_C_CPU0_SA_PAR")
	)
	(segment
		(start 339.954362 -253.383796)
		(end 339.954616 -253.38405)
		(width 0.20066)
		(layer "F.Cu")
		(net "M_C_CPU0_SA_PAR")
	)
	(segment
		(start 278.711914 -259.366766)
		(end 277.005542 -259.366766)
		(width 0.20066)
		(layer "F.Cu")
		(net "M_C_CPU0_SA_PAR")
	)
	(segment
		(start 272.74139 -259.60578)
		(end 272.502376 -259.366766)
		(width 0.20066)
		(layer "F.Cu")
		(net "M_C_CPU0_SA_PAR")
	)
	(segment
		(start 273.513042 -258.95554)
		(end 273.512788 -258.955286)
		(width 0.20066)
		(layer "F.Cu")
		(net "M_C_CPU0_SA_PAR")
	)
	(segment
		(start 274.152614 -258.95554)
		(end 274.143978 -258.95554)
		(width 0.101854)
		(layer "F.Cu")
		(net "M_C_CPU0_SA_PAR")
	)
	(segment
		(start 276.138386 -258.941824)
		(end 274.16633 -258.941824)
		(width 0.1016)
		(layer "F.Cu")
		(net "M_C_CPU0_SA_PAR")
	)
	(segment
		(start 273.512788 -258.955286)
		(end 273.37258 -259.095494)
		(width 0.20066)
		(layer "F.Cu")
		(net "M_C_CPU0_SA_PAR")
	)
	(segment
		(start 273.151346 -259.60578)
		(end 272.74139 -259.60578)
		(width 0.20066)
		(layer "F.Cu")
		(net "M_C_CPU0_SA_PAR")
	)
	(segment
		(start 276.5806 -258.941824)
		(end 276.469094 -258.941824)
		(width 0.20066)
		(layer "F.Cu")
		(net "M_C_CPU0_SA_PAR")
	)
	(segment
		(start 277.005542 -259.366766)
		(end 276.5806 -258.941824)
		(width 0.20066)
		(layer "F.Cu")
		(net "M_C_CPU0_SA_PAR")
	)
	(segment
		(start 279.816814 -259.366766)
		(end 278.711914 -259.366766)
		(width 0.20066)
		(layer "F.Cu")
		(net "M_C_CPU0_SA_PAR")
	)
	(segment
		(start 272.502376 -259.366766)
		(end 271.168114 -259.366766)
		(width 0.20066)
		(layer "F.Cu")
		(net "M_C_CPU0_SA_PAR")
	)
	(segment
		(start 334.050386 -254.184912)
		(end 332.888844 -253.02337)
		(width 0.088646)
		(layer "In4.Cu")
		(net "M_C_CPU0_SA_PAR")
	)
	(segment
		(start 327.957434 -255.50114)
		(end 319.643506 -255.50114)
		(width 0.18288)
		(layer "In4.Cu")
		(net "M_C_CPU0_SA_PAR")
	)
	(segment
		(start 332.375002 -253.02337)
		(end 330.435204 -253.02337)
		(width 0.18288)
		(layer "In4.Cu")
		(net "M_C_CPU0_SA_PAR")
	)
	(segment
		(start 330.435204 -253.02337)
		(end 327.957434 -255.50114)
		(width 0.18288)
		(layer "In4.Cu")
		(net "M_C_CPU0_SA_PAR")
	)
	(segment
		(start 282.03779 -259.366766)
		(end 279.816814 -259.366766)
		(width 0.18288)
		(layer "In4.Cu")
		(net "M_C_CPU0_SA_PAR")
	)
	(segment
		(start 283.314648 -260.643624)
		(end 282.03779 -259.366766)
		(width 0.18288)
		(layer "In4.Cu")
		(net "M_C_CPU0_SA_PAR")
	)
	(segment
		(start 339.954616 -253.919736)
		(end 339.835236 -253.919736)
		(width 0.088646)
		(layer "In4.Cu")
		(net "M_C_CPU0_SA_PAR")
	)
	(segment
		(start 301.343822 -257.990594)
		(end 298.082208 -257.990594)
		(width 0.18288)
		(layer "In4.Cu")
		(net "M_C_CPU0_SA_PAR")
	)
	(segment
		(start 287.186624 -258.94157)
		(end 285.48457 -260.643624)
		(width 0.18288)
		(layer "In4.Cu")
		(net "M_C_CPU0_SA_PAR")
	)
	(segment
		(start 332.888844 -253.02337)
		(end 332.375002 -253.02337)
		(width 0.088646)
		(layer "In4.Cu")
		(net "M_C_CPU0_SA_PAR")
	)
	(segment
		(start 285.48457 -260.643624)
		(end 283.314648 -260.643624)
		(width 0.18288)
		(layer "In4.Cu")
		(net "M_C_CPU0_SA_PAR")
	)
	(segment
		(start 304.270918 -257.408426)
		(end 301.343822 -257.990594)
		(width 0.18288)
		(layer "In4.Cu")
		(net "M_C_CPU0_SA_PAR")
	)
	(segment
		(start 313.866276 -257.408172)
		(end 313.866022 -257.408426)
		(width 0.18288)
		(layer "In4.Cu")
		(net "M_C_CPU0_SA_PAR")
	)
	(segment
		(start 319.643506 -255.50114)
		(end 315.039502 -257.408172)
		(width 0.18288)
		(layer "In4.Cu")
		(net "M_C_CPU0_SA_PAR")
	)
	(segment
		(start 313.866022 -257.408426)
		(end 304.270918 -257.408426)
		(width 0.18288)
		(layer "In4.Cu")
		(net "M_C_CPU0_SA_PAR")
	)
	(segment
		(start 338.272374 -254.237998)
		(end 338.26196 -254.244094)
		(width 0.088646)
		(layer "In4.Cu")
		(net "M_C_CPU0_SA_PAR")
	)
	(segment
		(start 315.039502 -257.408172)
		(end 313.866276 -257.408172)
		(width 0.18288)
		(layer "In4.Cu")
		(net "M_C_CPU0_SA_PAR")
	)
	(segment
		(start 338.84489 -254.254254)
		(end 338.827618 -254.244094)
		(width 0.088646)
		(layer "In4.Cu")
		(net "M_C_CPU0_SA_PAR")
	)
	(segment
		(start 297.131232 -258.94157)
		(end 287.186624 -258.94157)
		(width 0.18288)
		(layer "In4.Cu")
		(net "M_C_CPU0_SA_PAR")
	)
	(segment
		(start 298.082208 -257.990594)
		(end 297.131232 -258.94157)
		(width 0.18288)
		(layer "In4.Cu")
		(net "M_C_CPU0_SA_PAR")
	)
	(arc
		(start 339.305392 -254.197866)
		(mid 339.25266 -254.218512)
		(end 339.202268 -254.244348)
		(width 0.088646)
		(layer "In4.Cu")
		(net "M_C_CPU0_SA_PAR")
	)
	(arc
		(start 337.887564 -254.244094)
		(mid 337.604862 -254.168318)
		(end 337.32216 -254.244094)
		(width 0.088646)
		(layer "In4.Cu")
		(net "M_C_CPU0_SA_PAR")
	)
	(arc
		(start 335.44256 -254.244094)
		(mid 335.255362 -254.294237)
		(end 335.068164 -254.244094)
		(width 0.088646)
		(layer "In4.Cu")
		(net "M_C_CPU0_SA_PAR")
	)
	(arc
		(start 339.202268 -254.244348)
		(mid 339.024848 -254.29457)
		(end 338.84489 -254.254254)
		(width 0.088646)
		(layer "In4.Cu")
		(net "M_C_CPU0_SA_PAR")
	)
	(arc
		(start 334.128364 -254.244094)
		(mid 334.087434 -254.217061)
		(end 334.050386 -254.184912)
		(width 0.088646)
		(layer "In4.Cu")
		(net "M_C_CPU0_SA_PAR")
	)
	(arc
		(start 336.38236 -254.244094)
		(mid 336.195162 -254.294237)
		(end 336.007964 -254.244094)
		(width 0.088646)
		(layer "In4.Cu")
		(net "M_C_CPU0_SA_PAR")
	)
	(arc
		(start 336.947764 -254.244094)
		(mid 336.665062 -254.168318)
		(end 336.38236 -254.244094)
		(width 0.088646)
		(layer "In4.Cu")
		(net "M_C_CPU0_SA_PAR")
	)
	(arc
		(start 338.26196 -254.244094)
		(mid 338.074762 -254.294237)
		(end 337.887564 -254.244094)
		(width 0.088646)
		(layer "In4.Cu")
		(net "M_C_CPU0_SA_PAR")
	)
	(arc
		(start 334.50276 -254.244094)
		(mid 334.315562 -254.294237)
		(end 334.128364 -254.244094)
		(width 0.088646)
		(layer "In4.Cu")
		(net "M_C_CPU0_SA_PAR")
	)
	(arc
		(start 335.068164 -254.244094)
		(mid 334.785462 -254.168318)
		(end 334.50276 -254.244094)
		(width 0.088646)
		(layer "In4.Cu")
		(net "M_C_CPU0_SA_PAR")
	)
	(arc
		(start 336.007964 -254.244094)
		(mid 335.725262 -254.168318)
		(end 335.44256 -254.244094)
		(width 0.088646)
		(layer "In4.Cu")
		(net "M_C_CPU0_SA_PAR")
	)
	(arc
		(start 337.32216 -254.244094)
		(mid 337.134962 -254.294237)
		(end 336.947764 -254.244094)
		(width 0.088646)
		(layer "In4.Cu")
		(net "M_C_CPU0_SA_PAR")
	)
	(arc
		(start 339.835236 -253.919736)
		(mid 339.7045 -253.945741)
		(end 339.593682 -254.019812)
		(width 0.088646)
		(layer "In4.Cu")
		(net "M_C_CPU0_SA_PAR")
	)
	(arc
		(start 338.827618 -254.244094)
		(mid 338.550805 -254.168224)
		(end 338.272374 -254.237998)
		(width 0.088646)
		(layer "In4.Cu")
		(net "M_C_CPU0_SA_PAR")
	)
	(arc
		(start 339.593682 -254.019812)
		(mid 339.459806 -254.125464)
		(end 339.305392 -254.197866)
		(width 0.088646)
		(layer "In4.Cu")
		(net "M_C_CPU0_SA_PAR")
	)
	(segment
		(start 277.120858 -273.655536)
		(end 276.760686 -273.655536)
		(width 0.20066)
		(layer "F.Cu")
		(net "M_C_CPU0_SA_DQS_DP<9>")
	)
	(segment
		(start 344.653362 -259.894832)
		(end 344.653362 -260.430518)
		(width 0.20066)
		(layer "F.Cu")
		(net "M_C_CPU0_SA_DQS_DP<9>")
	)
	(segment
		(start 282.32227 -273.816572)
		(end 282.060904 -274.077938)
		(width 0.20066)
		(layer "F.Cu")
		(net "M_C_CPU0_SA_DQS_DP<9>")
	)
	(segment
		(start 280.820368 -273.652996)
		(end 280.315416 -273.652996)
		(width 0.20066)
		(layer "F.Cu")
		(net "M_C_CPU0_SA_DQS_DP<9>")
	)
	(segment
		(start 277.456392 -273.39163)
		(end 277.384764 -273.39163)
		(width 0.20066)
		(layer "F.Cu")
		(net "M_C_CPU0_SA_DQS_DP<9>")
	)
	(segment
		(start 277.834598 -273.39163)
		(end 277.456392 -273.39163)
		(width 0.101854)
		(layer "F.Cu")
		(net "M_C_CPU0_SA_DQS_DP<9>")
	)
	(segment
		(start 282.811982 -273.816572)
		(end 282.32227 -273.816572)
		(width 0.20066)
		(layer "F.Cu")
		(net "M_C_CPU0_SA_DQS_DP<9>")
	)
	(segment
		(start 281.456384 -274.077938)
		(end 280.820368 -273.652996)
		(width 0.20066)
		(layer "F.Cu")
		(net "M_C_CPU0_SA_DQS_DP<9>")
	)
	(segment
		(start 276.338284 -274.077938)
		(end 276.00402 -274.077938)
		(width 0.20066)
		(layer "F.Cu")
		(net "M_C_CPU0_SA_DQS_DP<9>")
	)
	(segment
		(start 277.384764 -273.39163)
		(end 277.120858 -273.655536)
		(width 0.20066)
		(layer "F.Cu")
		(net "M_C_CPU0_SA_DQS_DP<9>")
	)
	(segment
		(start 276.760686 -273.655536)
		(end 276.338284 -274.077938)
		(width 0.20066)
		(layer "F.Cu")
		(net "M_C_CPU0_SA_DQS_DP<9>")
	)
	(segment
		(start 282.060904 -274.077938)
		(end 281.456384 -274.077938)
		(width 0.20066)
		(layer "F.Cu")
		(net "M_C_CPU0_SA_DQS_DP<9>")
	)
	(segment
		(start 283.916882 -273.816572)
		(end 282.811982 -273.816572)
		(width 0.20066)
		(layer "F.Cu")
		(net "M_C_CPU0_SA_DQS_DP<9>")
	)
	(segment
		(start 279.96515 -273.39163)
		(end 279.912572 -273.39163)
		(width 0.101854)
		(layer "F.Cu")
		(net "M_C_CPU0_SA_DQS_DP<9>")
	)
	(segment
		(start 280.05405 -273.39163)
		(end 279.96515 -273.39163)
		(width 0.20066)
		(layer "F.Cu")
		(net "M_C_CPU0_SA_DQS_DP<9>")
	)
	(segment
		(start 279.912572 -273.39163)
		(end 277.834598 -273.39163)
		(width 0.1016)
		(layer "F.Cu")
		(net "M_C_CPU0_SA_DQS_DP<9>")
	)
	(segment
		(start 276.00402 -274.077938)
		(end 275.742654 -273.816572)
		(width 0.20066)
		(layer "F.Cu")
		(net "M_C_CPU0_SA_DQS_DP<9>")
	)
	(segment
		(start 280.315416 -273.652996)
		(end 280.05405 -273.39163)
		(width 0.20066)
		(layer "F.Cu")
		(net "M_C_CPU0_SA_DQS_DP<9>")
	)
	(segment
		(start 344.653362 -260.430518)
		(end 344.653108 -260.430772)
		(width 0.20066)
		(layer "F.Cu")
		(net "M_C_CPU0_SA_DQS_DP<9>")
	)
	(segment
		(start 275.742654 -273.816572)
		(end 275.268182 -273.816572)
		(width 0.20066)
		(layer "F.Cu")
		(net "M_C_CPU0_SA_DQS_DP<9>")
	)
	(segment
		(start 315.738256 -264.542524)
		(end 315.231526 -264.752328)
		(width 0.18288)
		(layer "In6.Cu")
		(net "M_C_CPU0_SA_DQS_DP<9>")
	)
	(segment
		(start 294.421052 -270.247364)
		(end 293.901876 -270.247364)
		(width 0.18288)
		(layer "In6.Cu")
		(net "M_C_CPU0_SA_DQS_DP<9>")
	)
	(segment
		(start 299.547026 -267.703046)
		(end 299.286676 -267.442696)
		(width 0.18288)
		(layer "In6.Cu")
		(net "M_C_CPU0_SA_DQS_DP<9>")
	)
	(segment
		(start 330.681076 -261.647432)
		(end 330.621386 -261.587742)
		(width 0.088646)
		(layer "In6.Cu")
		(net "M_C_CPU0_SA_DQS_DP<9>")
	)
	(segment
		(start 293.313612 -269.6591)
		(end 292.11905 -269.6591)
		(width 0.18288)
		(layer "In6.Cu")
		(net "M_C_CPU0_SA_DQS_DP<9>")
	)
	(segment
		(start 294.82542 -269.992856)
		(end 294.67556 -269.992856)
		(width 0.18288)
		(layer "In6.Cu")
		(net "M_C_CPU0_SA_DQS_DP<9>")
	)
	(segment
		(start 337.337146 -260.746494)
		(end 337.322414 -260.75513)
		(width 0.088646)
		(layer "In6.Cu")
		(net "M_C_CPU0_SA_DQS_DP<9>")
	)
	(segment
		(start 286.509968 -273.083274)
		(end 285.316422 -274.277074)
		(width 0.18288)
		(layer "In6.Cu")
		(net "M_C_CPU0_SA_DQS_DP<9>")
	)
	(segment
		(start 314.494418 -265.05789)
		(end 313.101736 -265.634724)
		(width 0.18288)
		(layer "In6.Cu")
		(net "M_C_CPU0_SA_DQS_DP<9>")
	)
	(segment
		(start 289.630612 -271.790668)
		(end 286.509968 -273.083274)
		(width 0.18288)
		(layer "In6.Cu")
		(net "M_C_CPU0_SA_DQS_DP<9>")
	)
	(segment
		(start 295.968928 -270.02232)
		(end 295.745916 -270.245332)
		(width 0.18288)
		(layer "In6.Cu")
		(net "M_C_CPU0_SA_DQS_DP<9>")
	)
	(segment
		(start 336.392774 -260.749034)
		(end 336.38236 -260.75513)
		(width 0.088646)
		(layer "In6.Cu")
		(net "M_C_CPU0_SA_DQS_DP<9>")
	)
	(segment
		(start 315.068966 -264.685018)
		(end 314.561728 -264.895076)
		(width 0.18288)
		(layer "In6.Cu")
		(net "M_C_CPU0_SA_DQS_DP<9>")
	)
	(segment
		(start 317.556642 -263.654286)
		(end 317.049404 -263.864344)
		(width 0.18288)
		(layer "In6.Cu")
		(net "M_C_CPU0_SA_DQS_DP<9>")
	)
	(segment
		(start 338.276946 -260.746494)
		(end 338.262214 -260.75513)
		(width 0.088646)
		(layer "In6.Cu")
		(net "M_C_CPU0_SA_DQS_DP<9>")
	)
	(segment
		(start 330.958444 -261.647432)
		(end 330.681076 -261.647432)
		(width 0.088646)
		(layer "In6.Cu")
		(net "M_C_CPU0_SA_DQS_DP<9>")
	)
	(segment
		(start 308.219602 -267.461746)
		(end 307.673502 -267.461746)
		(width 0.18288)
		(layer "In6.Cu")
		(net "M_C_CPU0_SA_DQS_DP<9>")
	)
	(segment
		(start 307.673502 -267.461746)
		(end 306.473352 -266.964668)
		(width 0.18288)
		(layer "In6.Cu")
		(net "M_C_CPU0_SA_DQS_DP<9>")
	)
	(segment
		(start 330.598018 -261.587742)
		(end 329.355196 -261.587742)
		(width 0.18288)
		(layer "In6.Cu")
		(net "M_C_CPU0_SA_DQS_DP<9>")
	)
	(segment
		(start 315.231526 -264.752328)
		(end 315.068966 -264.685018)
		(width 0.18288)
		(layer "In6.Cu")
		(net "M_C_CPU0_SA_DQS_DP<9>")
	)
	(segment
		(start 295.186608 -269.992856)
		(end 295.033954 -269.992602)
		(width 0.18288)
		(layer "In6.Cu")
		(net "M_C_CPU0_SA_DQS_DP<9>")
	)
	(segment
		(start 310.359806 -266.226544)
		(end 309.791354 -266.226544)
		(width 0.18288)
		(layer "In6.Cu")
		(net "M_C_CPU0_SA_DQS_DP<9>")
	)
	(segment
		(start 316.475364 -264.236962)
		(end 316.312804 -264.169652)
		(width 0.18288)
		(layer "In6.Cu")
		(net "M_C_CPU0_SA_DQS_DP<9>")
	)
	(segment
		(start 344.653108 -260.430772)
		(end 344.96629 -260.430772)
		(width 0.088646)
		(layer "In6.Cu")
		(net "M_C_CPU0_SA_DQS_DP<9>")
	)
	(segment
		(start 290.806378 -270.615156)
		(end 289.630612 -271.790668)
		(width 0.18288)
		(layer "In6.Cu")
		(net "M_C_CPU0_SA_DQS_DP<9>")
	)
	(segment
		(start 292.11905 -269.6591)
		(end 291.69995 -270.0782)
		(width 0.18288)
		(layer "In6.Cu")
		(net "M_C_CPU0_SA_DQS_DP<9>")
	)
	(segment
		(start 311.379616 -266.648946)
		(end 310.359806 -266.226544)
		(width 0.18288)
		(layer "In6.Cu")
		(net "M_C_CPU0_SA_DQS_DP<9>")
	)
	(segment
		(start 295.033954 -269.992602)
		(end 294.825674 -269.992602)
		(width 0.18288)
		(layer "In6.Cu")
		(net "M_C_CPU0_SA_DQS_DP<9>")
	)
	(segment
		(start 326.214486 -262.888984)
		(end 319.73012 -262.888984)
		(width 0.18288)
		(layer "In6.Cu")
		(net "M_C_CPU0_SA_DQS_DP<9>")
	)
	(segment
		(start 298.52112 -267.697204)
		(end 297.736768 -267.697204)
		(width 0.18288)
		(layer "In6.Cu")
		(net "M_C_CPU0_SA_DQS_DP<9>")
	)
	(segment
		(start 315.805566 -264.37971)
		(end 315.738256 -264.542524)
		(width 0.18288)
		(layer "In6.Cu")
		(net "M_C_CPU0_SA_DQS_DP<9>")
	)
	(segment
		(start 319.73012 -262.888984)
		(end 317.719202 -263.72185)
		(width 0.18288)
		(layer "In6.Cu")
		(net "M_C_CPU0_SA_DQS_DP<9>")
	)
	(segment
		(start 293.901876 -270.247364)
		(end 293.313612 -269.6591)
		(width 0.18288)
		(layer "In6.Cu")
		(net "M_C_CPU0_SA_DQS_DP<9>")
	)
	(segment
		(start 298.775628 -267.442696)
		(end 298.52112 -267.697204)
		(width 0.18288)
		(layer "In6.Cu")
		(net "M_C_CPU0_SA_DQS_DP<9>")
	)
	(segment
		(start 284.962346 -274.277074)
		(end 284.76448 -274.079208)
		(width 0.18288)
		(layer "In6.Cu")
		(net "M_C_CPU0_SA_DQS_DP<9>")
	)
	(segment
		(start 317.049404 -263.864344)
		(end 316.982094 -264.027158)
		(width 0.18288)
		(layer "In6.Cu")
		(net "M_C_CPU0_SA_DQS_DP<9>")
	)
	(segment
		(start 285.316422 -274.277074)
		(end 284.962346 -274.277074)
		(width 0.18288)
		(layer "In6.Cu")
		(net "M_C_CPU0_SA_DQS_DP<9>")
	)
	(segment
		(start 340.151974 -260.749034)
		(end 340.14156 -260.75513)
		(width 0.088646)
		(layer "In6.Cu")
		(net "M_C_CPU0_SA_DQS_DP<9>")
	)
	(segment
		(start 296.624756 -268.5161)
		(end 295.968928 -269.171928)
		(width 0.18288)
		(layer "In6.Cu")
		(net "M_C_CPU0_SA_DQS_DP<9>")
	)
	(segment
		(start 295.439084 -270.245332)
		(end 295.186608 -269.992856)
		(width 0.18288)
		(layer "In6.Cu")
		(net "M_C_CPU0_SA_DQS_DP<9>")
	)
	(segment
		(start 329.355196 -261.587742)
		(end 326.214486 -262.888984)
		(width 0.18288)
		(layer "In6.Cu")
		(net "M_C_CPU0_SA_DQS_DP<9>")
	)
	(segment
		(start 295.968928 -269.171928)
		(end 295.968928 -270.02232)
		(width 0.18288)
		(layer "In6.Cu")
		(net "M_C_CPU0_SA_DQS_DP<9>")
	)
	(segment
		(start 294.825674 -269.992602)
		(end 294.82542 -269.992856)
		(width 0.18288)
		(layer "In6.Cu")
		(net "M_C_CPU0_SA_DQS_DP<9>")
	)
	(segment
		(start 295.745916 -270.245332)
		(end 295.439084 -270.245332)
		(width 0.18288)
		(layer "In6.Cu")
		(net "M_C_CPU0_SA_DQS_DP<9>")
	)
	(segment
		(start 284.76448 -274.079208)
		(end 284.179518 -274.079208)
		(width 0.18288)
		(layer "In6.Cu")
		(net "M_C_CPU0_SA_DQS_DP<9>")
	)
	(segment
		(start 313.101736 -265.634724)
		(end 312.087514 -266.648946)
		(width 0.18288)
		(layer "In6.Cu")
		(net "M_C_CPU0_SA_DQS_DP<9>")
	)
	(segment
		(start 331.744828 -260.860794)
		(end 330.958444 -261.647432)
		(width 0.088646)
		(layer "In6.Cu")
		(net "M_C_CPU0_SA_DQS_DP<9>")
	)
	(segment
		(start 309.791354 -266.226544)
		(end 309.216806 -266.464288)
		(width 0.18288)
		(layer "In6.Cu")
		(net "M_C_CPU0_SA_DQS_DP<9>")
	)
	(segment
		(start 309.216806 -266.464288)
		(end 308.219602 -267.461746)
		(width 0.18288)
		(layer "In6.Cu")
		(net "M_C_CPU0_SA_DQS_DP<9>")
	)
	(segment
		(start 344.96629 -260.430772)
		(end 345.02344 -260.487922)
		(width 0.088646)
		(layer "In6.Cu")
		(net "M_C_CPU0_SA_DQS_DP<9>")
	)
	(segment
		(start 284.179518 -274.079208)
		(end 283.916882 -273.816572)
		(width 0.18288)
		(layer "In6.Cu")
		(net "M_C_CPU0_SA_DQS_DP<9>")
	)
	(segment
		(start 297.736768 -267.697204)
		(end 297.124882 -268.30909)
		(width 0.18288)
		(layer "In6.Cu")
		(net "M_C_CPU0_SA_DQS_DP<9>")
	)
	(segment
		(start 316.312804 -264.169652)
		(end 315.805566 -264.37971)
		(width 0.18288)
		(layer "In6.Cu")
		(net "M_C_CPU0_SA_DQS_DP<9>")
	)
	(segment
		(start 304.300128 -266.964668)
		(end 302.516286 -267.703046)
		(width 0.18288)
		(layer "In6.Cu")
		(net "M_C_CPU0_SA_DQS_DP<9>")
	)
	(segment
		(start 294.67556 -269.992856)
		(end 294.421052 -270.247364)
		(width 0.18288)
		(layer "In6.Cu")
		(net "M_C_CPU0_SA_DQS_DP<9>")
	)
	(segment
		(start 341.096346 -260.746494)
		(end 341.081614 -260.75513)
		(width 0.088646)
		(layer "In6.Cu")
		(net "M_C_CPU0_SA_DQS_DP<9>")
	)
	(segment
		(start 314.561728 -264.895076)
		(end 314.494418 -265.05789)
		(width 0.18288)
		(layer "In6.Cu")
		(net "M_C_CPU0_SA_DQS_DP<9>")
	)
	(segment
		(start 312.087514 -266.648946)
		(end 311.379616 -266.648946)
		(width 0.18288)
		(layer "In6.Cu")
		(net "M_C_CPU0_SA_DQS_DP<9>")
	)
	(segment
		(start 339.212428 -260.749034)
		(end 339.202014 -260.75513)
		(width 0.088646)
		(layer "In6.Cu")
		(net "M_C_CPU0_SA_DQS_DP<9>")
	)
	(segment
		(start 291.69995 -270.0782)
		(end 291.414962 -270.362934)
		(width 0.18288)
		(layer "In6.Cu")
		(net "M_C_CPU0_SA_DQS_DP<9>")
	)
	(segment
		(start 330.621386 -261.587742)
		(end 330.598018 -261.587742)
		(width 0.088646)
		(layer "In6.Cu")
		(net "M_C_CPU0_SA_DQS_DP<9>")
	)
	(segment
		(start 302.516286 -267.703046)
		(end 299.547026 -267.703046)
		(width 0.18288)
		(layer "In6.Cu")
		(net "M_C_CPU0_SA_DQS_DP<9>")
	)
	(segment
		(start 291.414962 -270.362934)
		(end 290.806378 -270.615156)
		(width 0.18288)
		(layer "In6.Cu")
		(net "M_C_CPU0_SA_DQS_DP<9>")
	)
	(segment
		(start 298.925234 -267.442442)
		(end 298.92498 -267.442696)
		(width 0.18288)
		(layer "In6.Cu")
		(net "M_C_CPU0_SA_DQS_DP<9>")
	)
	(segment
		(start 316.982094 -264.027158)
		(end 316.475364 -264.236962)
		(width 0.18288)
		(layer "In6.Cu")
		(net "M_C_CPU0_SA_DQS_DP<9>")
	)
	(segment
		(start 299.138594 -267.442442)
		(end 298.925234 -267.442442)
		(width 0.18288)
		(layer "In6.Cu")
		(net "M_C_CPU0_SA_DQS_DP<9>")
	)
	(segment
		(start 306.473352 -266.964668)
		(end 304.300128 -266.964668)
		(width 0.18288)
		(layer "In6.Cu")
		(net "M_C_CPU0_SA_DQS_DP<9>")
	)
	(segment
		(start 297.124882 -268.30909)
		(end 296.624756 -268.5161)
		(width 0.18288)
		(layer "In6.Cu")
		(net "M_C_CPU0_SA_DQS_DP<9>")
	)
	(segment
		(start 344.855292 -260.746494)
		(end 344.840306 -260.75513)
		(width 0.088646)
		(layer "In6.Cu")
		(net "M_C_CPU0_SA_DQS_DP<9>")
	)
	(segment
		(start 317.719202 -263.72185)
		(end 317.556642 -263.654286)
		(width 0.18288)
		(layer "In6.Cu")
		(net "M_C_CPU0_SA_DQS_DP<9>")
	)
	(segment
		(start 298.92498 -267.442696)
		(end 298.775628 -267.442696)
		(width 0.18288)
		(layer "In6.Cu")
		(net "M_C_CPU0_SA_DQS_DP<9>")
	)
	(segment
		(start 299.286676 -267.442696)
		(end 299.138594 -267.442442)
		(width 0.18288)
		(layer "In6.Cu")
		(net "M_C_CPU0_SA_DQS_DP<9>")
	)
	(arc
		(start 332.62316 -260.75513)
		(mid 332.474056 -260.803737)
		(end 332.318106 -260.787134)
		(width 0.088646)
		(layer "In6.Cu")
		(net "M_C_CPU0_SA_DQS_DP<9>")
	)
	(arc
		(start 342.58631 -260.75513)
		(mid 342.303862 -260.679515)
		(end 342.021414 -260.75513)
		(width 0.088646)
		(layer "In6.Cu")
		(net "M_C_CPU0_SA_DQS_DP<9>")
	)
	(arc
		(start 336.948018 -260.75513)
		(mid 336.671205 -260.679294)
		(end 336.392774 -260.749034)
		(width 0.088646)
		(layer "In6.Cu")
		(net "M_C_CPU0_SA_DQS_DP<9>")
	)
	(arc
		(start 335.068164 -260.75513)
		(mid 334.785462 -260.679388)
		(end 334.50276 -260.75513)
		(width 0.088646)
		(layer "In6.Cu")
		(net "M_C_CPU0_SA_DQS_DP<9>")
	)
	(arc
		(start 334.50276 -260.75513)
		(mid 334.315562 -260.805273)
		(end 334.128364 -260.75513)
		(width 0.088646)
		(layer "In6.Cu")
		(net "M_C_CPU0_SA_DQS_DP<9>")
	)
	(arc
		(start 335.44256 -260.75513)
		(mid 335.255362 -260.805273)
		(end 335.068164 -260.75513)
		(width 0.088646)
		(layer "In6.Cu")
		(net "M_C_CPU0_SA_DQS_DP<9>")
	)
	(arc
		(start 336.007964 -260.75513)
		(mid 335.725262 -260.679388)
		(end 335.44256 -260.75513)
		(width 0.088646)
		(layer "In6.Cu")
		(net "M_C_CPU0_SA_DQS_DP<9>")
	)
	(arc
		(start 342.021414 -260.75513)
		(mid 341.834216 -260.805273)
		(end 341.647018 -260.75513)
		(width 0.088646)
		(layer "In6.Cu")
		(net "M_C_CPU0_SA_DQS_DP<9>")
	)
	(arc
		(start 338.262214 -260.75513)
		(mid 338.075016 -260.805273)
		(end 337.887818 -260.75513)
		(width 0.088646)
		(layer "In6.Cu")
		(net "M_C_CPU0_SA_DQS_DP<9>")
	)
	(arc
		(start 344.46591 -260.75513)
		(mid 344.183462 -260.679515)
		(end 343.901014 -260.75513)
		(width 0.088646)
		(layer "In6.Cu")
		(net "M_C_CPU0_SA_DQS_DP<9>")
	)
	(arc
		(start 334.128364 -260.75513)
		(mid 333.845662 -260.679388)
		(end 333.56296 -260.75513)
		(width 0.088646)
		(layer "In6.Cu")
		(net "M_C_CPU0_SA_DQS_DP<9>")
	)
	(arc
		(start 339.767164 -260.75513)
		(mid 339.490605 -260.679421)
		(end 339.212428 -260.749034)
		(width 0.088646)
		(layer "In6.Cu")
		(net "M_C_CPU0_SA_DQS_DP<9>")
	)
	(arc
		(start 341.647018 -260.75513)
		(mid 341.372789 -260.679205)
		(end 341.096346 -260.746494)
		(width 0.088646)
		(layer "In6.Cu")
		(net "M_C_CPU0_SA_DQS_DP<9>")
	)
	(arc
		(start 340.14156 -260.75513)
		(mid 339.954362 -260.805273)
		(end 339.767164 -260.75513)
		(width 0.088646)
		(layer "In6.Cu")
		(net "M_C_CPU0_SA_DQS_DP<9>")
	)
	(arc
		(start 341.081614 -260.75513)
		(mid 340.894416 -260.805273)
		(end 340.707218 -260.75513)
		(width 0.088646)
		(layer "In6.Cu")
		(net "M_C_CPU0_SA_DQS_DP<9>")
	)
	(arc
		(start 339.202014 -260.75513)
		(mid 339.014816 -260.805273)
		(end 338.827618 -260.75513)
		(width 0.088646)
		(layer "In6.Cu")
		(net "M_C_CPU0_SA_DQS_DP<9>")
	)
	(arc
		(start 338.827618 -260.75513)
		(mid 338.553389 -260.679205)
		(end 338.276946 -260.746494)
		(width 0.088646)
		(layer "In6.Cu")
		(net "M_C_CPU0_SA_DQS_DP<9>")
	)
	(arc
		(start 345.02344 -260.487922)
		(mid 344.967224 -260.635336)
		(end 344.855292 -260.746494)
		(width 0.088646)
		(layer "In6.Cu")
		(net "M_C_CPU0_SA_DQS_DP<9>")
	)
	(arc
		(start 340.707218 -260.75513)
		(mid 340.430405 -260.679294)
		(end 340.151974 -260.749034)
		(width 0.088646)
		(layer "In6.Cu")
		(net "M_C_CPU0_SA_DQS_DP<9>")
	)
	(arc
		(start 343.526618 -260.75513)
		(mid 343.243662 -260.679261)
		(end 342.960706 -260.75513)
		(width 0.088646)
		(layer "In6.Cu")
		(net "M_C_CPU0_SA_DQS_DP<9>")
	)
	(arc
		(start 333.188564 -260.75513)
		(mid 332.905862 -260.679388)
		(end 332.62316 -260.75513)
		(width 0.088646)
		(layer "In6.Cu")
		(net "M_C_CPU0_SA_DQS_DP<9>")
	)
	(arc
		(start 343.901014 -260.75513)
		(mid 343.713816 -260.805273)
		(end 343.526618 -260.75513)
		(width 0.088646)
		(layer "In6.Cu")
		(net "M_C_CPU0_SA_DQS_DP<9>")
	)
	(arc
		(start 332.318106 -260.787134)
		(mid 332.118315 -260.749647)
		(end 331.91577 -260.766814)
		(width 0.088646)
		(layer "In6.Cu")
		(net "M_C_CPU0_SA_DQS_DP<9>")
	)
	(arc
		(start 336.38236 -260.75513)
		(mid 336.195162 -260.805273)
		(end 336.007964 -260.75513)
		(width 0.088646)
		(layer "In6.Cu")
		(net "M_C_CPU0_SA_DQS_DP<9>")
	)
	(arc
		(start 337.322414 -260.75513)
		(mid 337.135216 -260.805273)
		(end 336.948018 -260.75513)
		(width 0.088646)
		(layer "In6.Cu")
		(net "M_C_CPU0_SA_DQS_DP<9>")
	)
	(arc
		(start 333.56296 -260.75513)
		(mid 333.375762 -260.805273)
		(end 333.188564 -260.75513)
		(width 0.088646)
		(layer "In6.Cu")
		(net "M_C_CPU0_SA_DQS_DP<9>")
	)
	(arc
		(start 337.887818 -260.75513)
		(mid 337.613589 -260.679205)
		(end 337.337146 -260.746494)
		(width 0.088646)
		(layer "In6.Cu")
		(net "M_C_CPU0_SA_DQS_DP<9>")
	)
	(arc
		(start 331.91577 -260.766814)
		(mid 331.823597 -260.801615)
		(end 331.744828 -260.860794)
		(width 0.088646)
		(layer "In6.Cu")
		(net "M_C_CPU0_SA_DQS_DP<9>")
	)
	(arc
		(start 342.960706 -260.75513)
		(mid 342.773508 -260.805273)
		(end 342.58631 -260.75513)
		(width 0.088646)
		(layer "In6.Cu")
		(net "M_C_CPU0_SA_DQS_DP<9>")
	)
	(arc
		(start 344.840306 -260.75513)
		(mid 344.653108 -260.805273)
		(end 344.46591 -260.75513)
		(width 0.088646)
		(layer "In6.Cu")
		(net "M_C_CPU0_SA_DQS_DP<9>")
	)
	(segment
		(start 345.593162 -264.778236)
		(end 345.593416 -265.314176)
		(width 0.20066)
		(layer "F.Cu")
		(net "M_C_CPU0_SA_DQS_DP<8>")
	)
	(segment
		(start 282.32227 -283.166566)
		(end 282.060904 -283.427932)
		(width 0.20066)
		(layer "F.Cu")
		(net "M_C_CPU0_SA_DQS_DP<8>")
	)
	(segment
		(start 276.338284 -283.427932)
		(end 276.00402 -283.427932)
		(width 0.20066)
		(layer "F.Cu")
		(net "M_C_CPU0_SA_DQS_DP<8>")
	)
	(segment
		(start 276.760686 -283.00553)
		(end 276.338284 -283.427932)
		(width 0.20066)
		(layer "F.Cu")
		(net "M_C_CPU0_SA_DQS_DP<8>")
	)
	(segment
		(start 276.00402 -283.427932)
		(end 275.742654 -283.166566)
		(width 0.20066)
		(layer "F.Cu")
		(net "M_C_CPU0_SA_DQS_DP<8>")
	)
	(segment
		(start 280.054304 -282.741878)
		(end 279.912826 -282.741878)
		(width 0.20066)
		(layer "F.Cu")
		(net "M_C_CPU0_SA_DQS_DP<8>")
	)
	(segment
		(start 282.811982 -283.166566)
		(end 282.32227 -283.166566)
		(width 0.20066)
		(layer "F.Cu")
		(net "M_C_CPU0_SA_DQS_DP<8>")
	)
	(segment
		(start 277.834598 -282.741624)
		(end 277.593298 -282.741624)
		(width 0.101854)
		(layer "F.Cu")
		(net "M_C_CPU0_SA_DQS_DP<8>")
	)
	(segment
		(start 281.456384 -283.427932)
		(end 280.820368 -283.00299)
		(width 0.20066)
		(layer "F.Cu")
		(net "M_C_CPU0_SA_DQS_DP<8>")
	)
	(segment
		(start 277.58771 -282.736036)
		(end 277.390352 -282.736036)
		(width 0.20066)
		(layer "F.Cu")
		(net "M_C_CPU0_SA_DQS_DP<8>")
	)
	(segment
		(start 277.120858 -283.00553)
		(end 276.760686 -283.00553)
		(width 0.20066)
		(layer "F.Cu")
		(net "M_C_CPU0_SA_DQS_DP<8>")
	)
	(segment
		(start 277.593298 -282.741624)
		(end 277.58771 -282.736036)
		(width 0.101854)
		(layer "F.Cu")
		(net "M_C_CPU0_SA_DQS_DP<8>")
	)
	(segment
		(start 283.916882 -283.166566)
		(end 282.811982 -283.166566)
		(width 0.20066)
		(layer "F.Cu")
		(net "M_C_CPU0_SA_DQS_DP<8>")
	)
	(segment
		(start 280.820368 -283.00299)
		(end 280.315416 -283.00299)
		(width 0.20066)
		(layer "F.Cu")
		(net "M_C_CPU0_SA_DQS_DP<8>")
	)
	(segment
		(start 282.060904 -283.427932)
		(end 281.456384 -283.427932)
		(width 0.20066)
		(layer "F.Cu")
		(net "M_C_CPU0_SA_DQS_DP<8>")
	)
	(segment
		(start 275.742654 -283.166566)
		(end 275.268182 -283.166566)
		(width 0.20066)
		(layer "F.Cu")
		(net "M_C_CPU0_SA_DQS_DP<8>")
	)
	(segment
		(start 279.912572 -282.741624)
		(end 277.834598 -282.741624)
		(width 0.1016)
		(layer "F.Cu")
		(net "M_C_CPU0_SA_DQS_DP<8>")
	)
	(segment
		(start 279.912826 -282.741878)
		(end 279.912572 -282.741624)
		(width 0.1016)
		(layer "F.Cu")
		(net "M_C_CPU0_SA_DQS_DP<8>")
	)
	(segment
		(start 277.390352 -282.736036)
		(end 277.120858 -283.00553)
		(width 0.20066)
		(layer "F.Cu")
		(net "M_C_CPU0_SA_DQS_DP<8>")
	)
	(segment
		(start 280.315416 -283.00299)
		(end 280.054304 -282.741878)
		(width 0.20066)
		(layer "F.Cu")
		(net "M_C_CPU0_SA_DQS_DP<8>")
	)
	(segment
		(start 299.565822 -278.774906)
		(end 299.282612 -278.491696)
		(width 0.18288)
		(layer "In6.Cu")
		(net "M_C_CPU0_SA_DQS_DP<8>")
	)
	(segment
		(start 302.748188 -277.240492)
		(end 301.968662 -277.240492)
		(width 0.18288)
		(layer "In6.Cu")
		(net "M_C_CPU0_SA_DQS_DP<8>")
	)
	(segment
		(start 284.684724 -283.427678)
		(end 284.177994 -283.427678)
		(width 0.18288)
		(layer "In6.Cu")
		(net "M_C_CPU0_SA_DQS_DP<8>")
	)
	(segment
		(start 343.056464 -264.824718)
		(end 343.041732 -264.816082)
		(width 0.088646)
		(layer "In6.Cu")
		(net "M_C_CPU0_SA_DQS_DP<8>")
	)
	(segment
		(start 331.338936 -266.89558)
		(end 331.06233 -266.89558)
		(width 0.088646)
		(layer "In6.Cu")
		(net "M_C_CPU0_SA_DQS_DP<8>")
	)
	(segment
		(start 341.176864 -264.824718)
		(end 341.162132 -264.816082)
		(width 0.088646)
		(layer "In6.Cu")
		(net "M_C_CPU0_SA_DQS_DP<8>")
	)
	(segment
		(start 289.299396 -282.996132)
		(end 288.194496 -282.996132)
		(width 0.18288)
		(layer "In6.Cu")
		(net "M_C_CPU0_SA_DQS_DP<8>")
	)
	(segment
		(start 295.182544 -279.341834)
		(end 294.681402 -279.341834)
		(width 0.18288)
		(layer "In6.Cu")
		(net "M_C_CPU0_SA_DQS_DP<8>")
	)
	(segment
		(start 297.75277 -278.753316)
		(end 296.903902 -279.602184)
		(width 0.18288)
		(layer "In6.Cu")
		(net "M_C_CPU0_SA_DQS_DP<8>")
	)
	(segment
		(start 331.00264 -266.83589)
		(end 330.979272 -266.83589)
		(width 0.088646)
		(layer "In6.Cu")
		(net "M_C_CPU0_SA_DQS_DP<8>")
	)
	(segment
		(start 345.280742 -265.314176)
		(end 345.214956 -265.24839)
		(width 0.088646)
		(layer "In6.Cu")
		(net "M_C_CPU0_SA_DQS_DP<8>")
	)
	(segment
		(start 343.996264 -264.824718)
		(end 343.981532 -264.816082)
		(width 0.088646)
		(layer "In6.Cu")
		(net "M_C_CPU0_SA_DQS_DP<8>")
	)
	(segment
		(start 330.035408 -266.83589)
		(end 327.004426 -268.091158)
		(width 0.18288)
		(layer "In6.Cu")
		(net "M_C_CPU0_SA_DQS_DP<8>")
	)
	(segment
		(start 293.51097 -279.591008)
		(end 291.904166 -281.197812)
		(width 0.18288)
		(layer "In6.Cu")
		(net "M_C_CPU0_SA_DQS_DP<8>")
	)
	(segment
		(start 296.903902 -279.602184)
		(end 295.442894 -279.602184)
		(width 0.18288)
		(layer "In6.Cu")
		(net "M_C_CPU0_SA_DQS_DP<8>")
	)
	(segment
		(start 345.593416 -265.314176)
		(end 345.280742 -265.314176)
		(width 0.088646)
		(layer "In6.Cu")
		(net "M_C_CPU0_SA_DQS_DP<8>")
	)
	(segment
		(start 291.097716 -281.197812)
		(end 289.299396 -282.996132)
		(width 0.18288)
		(layer "In6.Cu")
		(net "M_C_CPU0_SA_DQS_DP<8>")
	)
	(segment
		(start 287.58261 -283.608018)
		(end 284.865064 -283.608018)
		(width 0.18288)
		(layer "In6.Cu")
		(net "M_C_CPU0_SA_DQS_DP<8>")
	)
	(segment
		(start 284.865064 -283.608018)
		(end 284.684724 -283.427678)
		(width 0.18288)
		(layer "In6.Cu")
		(net "M_C_CPU0_SA_DQS_DP<8>")
	)
	(segment
		(start 332.810612 -265.30427)
		(end 332.810612 -265.314176)
		(width 0.088646)
		(layer "In6.Cu")
		(net "M_C_CPU0_SA_DQS_DP<8>")
	)
	(segment
		(start 330.979272 -266.83589)
		(end 330.035408 -266.83589)
		(width 0.18288)
		(layer "In6.Cu")
		(net "M_C_CPU0_SA_DQS_DP<8>")
	)
	(segment
		(start 284.177994 -283.427678)
		(end 283.916882 -283.166566)
		(width 0.18288)
		(layer "In6.Cu")
		(net "M_C_CPU0_SA_DQS_DP<8>")
	)
	(segment
		(start 344.936064 -264.824718)
		(end 344.921332 -264.816082)
		(width 0.088646)
		(layer "In6.Cu")
		(net "M_C_CPU0_SA_DQS_DP<8>")
	)
	(segment
		(start 332.63205 -265.633454)
		(end 332.62316 -265.638534)
		(width 0.088646)
		(layer "In6.Cu")
		(net "M_C_CPU0_SA_DQS_DP<8>")
	)
	(segment
		(start 310.941974 -275.553678)
		(end 307.16855 -275.553678)
		(width 0.18288)
		(layer "In6.Cu")
		(net "M_C_CPU0_SA_DQS_DP<8>")
	)
	(segment
		(start 300.434248 -278.774906)
		(end 299.565822 -278.774906)
		(width 0.18288)
		(layer "In6.Cu")
		(net "M_C_CPU0_SA_DQS_DP<8>")
	)
	(segment
		(start 313.577986 -274.453096)
		(end 312.060336 -275.970746)
		(width 0.18288)
		(layer "In6.Cu")
		(net "M_C_CPU0_SA_DQS_DP<8>")
	)
	(segment
		(start 291.904166 -281.197812)
		(end 291.097716 -281.197812)
		(width 0.18288)
		(layer "In6.Cu")
		(net "M_C_CPU0_SA_DQS_DP<8>")
	)
	(segment
		(start 326.423274 -268.091158)
		(end 318.715644 -271.284192)
		(width 0.18288)
		(layer "In6.Cu")
		(net "M_C_CPU0_SA_DQS_DP<8>")
	)
	(segment
		(start 339.682328 -264.818622)
		(end 339.671914 -264.824718)
		(width 0.088646)
		(layer "In6.Cu")
		(net "M_C_CPU0_SA_DQS_DP<8>")
	)
	(segment
		(start 344.936826 -264.825226)
		(end 344.936064 -264.824718)
		(width 0.088646)
		(layer "In6.Cu")
		(net "M_C_CPU0_SA_DQS_DP<8>")
	)
	(segment
		(start 311.359042 -275.970746)
		(end 310.941974 -275.553678)
		(width 0.18288)
		(layer "In6.Cu")
		(net "M_C_CPU0_SA_DQS_DP<8>")
	)
	(segment
		(start 339.297518 -264.824718)
		(end 339.287104 -264.818622)
		(width 0.088646)
		(layer "In6.Cu")
		(net "M_C_CPU0_SA_DQS_DP<8>")
	)
	(segment
		(start 331.06233 -266.89558)
		(end 331.00264 -266.83589)
		(width 0.088646)
		(layer "In6.Cu")
		(net "M_C_CPU0_SA_DQS_DP<8>")
	)
	(segment
		(start 301.968662 -277.240492)
		(end 300.434248 -278.774906)
		(width 0.18288)
		(layer "In6.Cu")
		(net "M_C_CPU0_SA_DQS_DP<8>")
	)
	(segment
		(start 295.442894 -279.602184)
		(end 295.182544 -279.341834)
		(width 0.18288)
		(layer "In6.Cu")
		(net "M_C_CPU0_SA_DQS_DP<8>")
	)
	(segment
		(start 294.681402 -279.341834)
		(end 294.432228 -279.591008)
		(width 0.18288)
		(layer "In6.Cu")
		(net "M_C_CPU0_SA_DQS_DP<8>")
	)
	(segment
		(start 342.116664 -264.824718)
		(end 342.101932 -264.816082)
		(width 0.088646)
		(layer "In6.Cu")
		(net "M_C_CPU0_SA_DQS_DP<8>")
	)
	(segment
		(start 306.538884 -276.183344)
		(end 303.805336 -276.183344)
		(width 0.18288)
		(layer "In6.Cu")
		(net "M_C_CPU0_SA_DQS_DP<8>")
	)
	(segment
		(start 299.282612 -278.491696)
		(end 298.78147 -278.491696)
		(width 0.18288)
		(layer "In6.Cu")
		(net "M_C_CPU0_SA_DQS_DP<8>")
	)
	(segment
		(start 332.506066 -265.72845)
		(end 331.338936 -266.89558)
		(width 0.088646)
		(layer "In6.Cu")
		(net "M_C_CPU0_SA_DQS_DP<8>")
	)
	(segment
		(start 288.194496 -282.996132)
		(end 287.58261 -283.608018)
		(width 0.18288)
		(layer "In6.Cu")
		(net "M_C_CPU0_SA_DQS_DP<8>")
	)
	(segment
		(start 315.546994 -274.453096)
		(end 313.577986 -274.453096)
		(width 0.18288)
		(layer "In6.Cu")
		(net "M_C_CPU0_SA_DQS_DP<8>")
	)
	(segment
		(start 344.94216 -264.828274)
		(end 344.936826 -264.825226)
		(width 0.088646)
		(layer "In6.Cu")
		(net "M_C_CPU0_SA_DQS_DP<8>")
	)
	(segment
		(start 303.805336 -276.183344)
		(end 302.748188 -277.240492)
		(width 0.18288)
		(layer "In6.Cu")
		(net "M_C_CPU0_SA_DQS_DP<8>")
	)
	(segment
		(start 312.060336 -275.970746)
		(end 311.359042 -275.970746)
		(width 0.18288)
		(layer "In6.Cu")
		(net "M_C_CPU0_SA_DQS_DP<8>")
	)
	(segment
		(start 294.432228 -279.591008)
		(end 293.51097 -279.591008)
		(width 0.18288)
		(layer "In6.Cu")
		(net "M_C_CPU0_SA_DQS_DP<8>")
	)
	(segment
		(start 298.51985 -278.753316)
		(end 297.75277 -278.753316)
		(width 0.18288)
		(layer "In6.Cu")
		(net "M_C_CPU0_SA_DQS_DP<8>")
	)
	(segment
		(start 307.16855 -275.553678)
		(end 306.538884 -276.183344)
		(width 0.18288)
		(layer "In6.Cu")
		(net "M_C_CPU0_SA_DQS_DP<8>")
	)
	(segment
		(start 327.004426 -268.091158)
		(end 326.423274 -268.091158)
		(width 0.18288)
		(layer "In6.Cu")
		(net "M_C_CPU0_SA_DQS_DP<8>")
	)
	(segment
		(start 318.715644 -271.284192)
		(end 315.546994 -274.453096)
		(width 0.18288)
		(layer "In6.Cu")
		(net "M_C_CPU0_SA_DQS_DP<8>")
	)
	(segment
		(start 298.78147 -278.491696)
		(end 298.51985 -278.753316)
		(width 0.18288)
		(layer "In6.Cu")
		(net "M_C_CPU0_SA_DQS_DP<8>")
	)
	(arc
		(start 339.287104 -264.818622)
		(mid 339.008672 -264.748776)
		(end 338.73186 -264.824718)
		(width 0.088646)
		(layer "In6.Cu")
		(net "M_C_CPU0_SA_DQS_DP<8>")
	)
	(arc
		(start 336.85226 -264.824718)
		(mid 336.665062 -264.874861)
		(end 336.477864 -264.824718)
		(width 0.088646)
		(layer "In6.Cu")
		(net "M_C_CPU0_SA_DQS_DP<8>")
	)
	(arc
		(start 343.43086 -264.824718)
		(mid 343.243662 -264.874861)
		(end 343.056464 -264.824718)
		(width 0.088646)
		(layer "In6.Cu")
		(net "M_C_CPU0_SA_DQS_DP<8>")
	)
	(arc
		(start 340.61146 -264.824718)
		(mid 340.424262 -264.874861)
		(end 340.237064 -264.824718)
		(width 0.088646)
		(layer "In6.Cu")
		(net "M_C_CPU0_SA_DQS_DP<8>")
	)
	(arc
		(start 338.357464 -264.824718)
		(mid 338.074762 -264.748942)
		(end 337.79206 -264.824718)
		(width 0.088646)
		(layer "In6.Cu")
		(net "M_C_CPU0_SA_DQS_DP<8>")
	)
	(arc
		(start 333.658464 -264.824718)
		(mid 333.097488 -264.822187)
		(end 332.810612 -265.30427)
		(width 0.088646)
		(layer "In6.Cu")
		(net "M_C_CPU0_SA_DQS_DP<8>")
	)
	(arc
		(start 340.237064 -264.824718)
		(mid 339.960505 -264.748975)
		(end 339.682328 -264.818622)
		(width 0.088646)
		(layer "In6.Cu")
		(net "M_C_CPU0_SA_DQS_DP<8>")
	)
	(arc
		(start 341.55126 -264.824718)
		(mid 341.364062 -264.874861)
		(end 341.176864 -264.824718)
		(width 0.088646)
		(layer "In6.Cu")
		(net "M_C_CPU0_SA_DQS_DP<8>")
	)
	(arc
		(start 345.214956 -265.24839)
		(mid 345.213655 -265.237963)
		(end 345.212162 -265.227562)
		(width 0.088646)
		(layer "In6.Cu")
		(net "M_C_CPU0_SA_DQS_DP<8>")
	)
	(arc
		(start 334.598264 -264.824718)
		(mid 334.315562 -264.748942)
		(end 334.03286 -264.824718)
		(width 0.088646)
		(layer "In6.Cu")
		(net "M_C_CPU0_SA_DQS_DP<8>")
	)
	(arc
		(start 341.162132 -264.816082)
		(mid 340.885657 -264.748762)
		(end 340.61146 -264.824718)
		(width 0.088646)
		(layer "In6.Cu")
		(net "M_C_CPU0_SA_DQS_DP<8>")
	)
	(arc
		(start 337.417664 -264.824718)
		(mid 337.134962 -264.748942)
		(end 336.85226 -264.824718)
		(width 0.088646)
		(layer "In6.Cu")
		(net "M_C_CPU0_SA_DQS_DP<8>")
	)
	(arc
		(start 343.981532 -264.816082)
		(mid 343.705057 -264.748762)
		(end 343.43086 -264.824718)
		(width 0.088646)
		(layer "In6.Cu")
		(net "M_C_CPU0_SA_DQS_DP<8>")
	)
	(arc
		(start 334.03286 -264.824718)
		(mid 333.845662 -264.874861)
		(end 333.658464 -264.824718)
		(width 0.088646)
		(layer "In6.Cu")
		(net "M_C_CPU0_SA_DQS_DP<8>")
	)
	(arc
		(start 334.97266 -264.824718)
		(mid 334.785462 -264.874861)
		(end 334.598264 -264.824718)
		(width 0.088646)
		(layer "In6.Cu")
		(net "M_C_CPU0_SA_DQS_DP<8>")
	)
	(arc
		(start 344.37066 -264.824718)
		(mid 344.183462 -264.874861)
		(end 343.996264 -264.824718)
		(width 0.088646)
		(layer "In6.Cu")
		(net "M_C_CPU0_SA_DQS_DP<8>")
	)
	(arc
		(start 345.212162 -265.227562)
		(mid 345.121898 -264.997652)
		(end 344.94216 -264.828274)
		(width 0.088646)
		(layer "In6.Cu")
		(net "M_C_CPU0_SA_DQS_DP<8>")
	)
	(arc
		(start 338.73186 -264.824718)
		(mid 338.544662 -264.874861)
		(end 338.357464 -264.824718)
		(width 0.088646)
		(layer "In6.Cu")
		(net "M_C_CPU0_SA_DQS_DP<8>")
	)
	(arc
		(start 342.101932 -264.816082)
		(mid 341.825457 -264.748762)
		(end 341.55126 -264.824718)
		(width 0.088646)
		(layer "In6.Cu")
		(net "M_C_CPU0_SA_DQS_DP<8>")
	)
	(arc
		(start 332.810612 -265.314176)
		(mid 332.762933 -265.497076)
		(end 332.63205 -265.633454)
		(width 0.088646)
		(layer "In6.Cu")
		(net "M_C_CPU0_SA_DQS_DP<8>")
	)
	(arc
		(start 335.91246 -264.824718)
		(mid 335.725262 -264.874861)
		(end 335.538064 -264.824718)
		(width 0.088646)
		(layer "In6.Cu")
		(net "M_C_CPU0_SA_DQS_DP<8>")
	)
	(arc
		(start 332.62316 -265.638534)
		(mid 332.561665 -265.679653)
		(end 332.506066 -265.72845)
		(width 0.088646)
		(layer "In6.Cu")
		(net "M_C_CPU0_SA_DQS_DP<8>")
	)
	(arc
		(start 336.477864 -264.824718)
		(mid 336.195162 -264.748942)
		(end 335.91246 -264.824718)
		(width 0.088646)
		(layer "In6.Cu")
		(net "M_C_CPU0_SA_DQS_DP<8>")
	)
	(arc
		(start 339.671914 -264.824718)
		(mid 339.484716 -264.874861)
		(end 339.297518 -264.824718)
		(width 0.088646)
		(layer "In6.Cu")
		(net "M_C_CPU0_SA_DQS_DP<8>")
	)
	(arc
		(start 337.79206 -264.824718)
		(mid 337.604862 -264.874861)
		(end 337.417664 -264.824718)
		(width 0.088646)
		(layer "In6.Cu")
		(net "M_C_CPU0_SA_DQS_DP<8>")
	)
	(arc
		(start 342.49106 -264.824718)
		(mid 342.303862 -264.874861)
		(end 342.116664 -264.824718)
		(width 0.088646)
		(layer "In6.Cu")
		(net "M_C_CPU0_SA_DQS_DP<8>")
	)
	(arc
		(start 344.921332 -264.816082)
		(mid 344.644857 -264.748762)
		(end 344.37066 -264.824718)
		(width 0.088646)
		(layer "In6.Cu")
		(net "M_C_CPU0_SA_DQS_DP<8>")
	)
	(arc
		(start 343.041732 -264.816082)
		(mid 342.765257 -264.748762)
		(end 342.49106 -264.824718)
		(width 0.088646)
		(layer "In6.Cu")
		(net "M_C_CPU0_SA_DQS_DP<8>")
	)
	(arc
		(start 335.538064 -264.824718)
		(mid 335.255362 -264.748942)
		(end 334.97266 -264.824718)
		(width 0.088646)
		(layer "In6.Cu")
		(net "M_C_CPU0_SA_DQS_DP<8>")
	)
	(segment
		(start 280.315416 -292.352984)
		(end 280.054304 -292.091872)
		(width 0.20066)
		(layer "F.Cu")
		(net "M_C_CPU0_SA_DQS_DP<7>")
	)
	(segment
		(start 282.811982 -292.516814)
		(end 282.322016 -292.516814)
		(width 0.20066)
		(layer "F.Cu")
		(net "M_C_CPU0_SA_DQS_DP<7>")
	)
	(segment
		(start 281.456384 -292.777926)
		(end 280.820368 -292.352984)
		(width 0.20066)
		(layer "F.Cu")
		(net "M_C_CPU0_SA_DQS_DP<7>")
	)
	(segment
		(start 277.593552 -292.091872)
		(end 277.58771 -292.08603)
		(width 0.101854)
		(layer "F.Cu")
		(net "M_C_CPU0_SA_DQS_DP<7>")
	)
	(segment
		(start 280.054304 -292.091872)
		(end 279.912826 -292.091872)
		(width 0.20066)
		(layer "F.Cu")
		(net "M_C_CPU0_SA_DQS_DP<7>")
	)
	(segment
		(start 277.834344 -292.091872)
		(end 277.593552 -292.091872)
		(width 0.101854)
		(layer "F.Cu")
		(net "M_C_CPU0_SA_DQS_DP<7>")
	)
	(segment
		(start 277.58771 -292.08603)
		(end 277.390352 -292.08603)
		(width 0.20066)
		(layer "F.Cu")
		(net "M_C_CPU0_SA_DQS_DP<7>")
	)
	(segment
		(start 279.912826 -292.091872)
		(end 277.834344 -292.091872)
		(width 0.1016)
		(layer "F.Cu")
		(net "M_C_CPU0_SA_DQS_DP<7>")
	)
	(segment
		(start 341.364316 -267.219938)
		(end 341.364062 -267.755878)
		(width 0.20066)
		(layer "F.Cu")
		(net "M_C_CPU0_SA_DQS_DP<7>")
	)
	(segment
		(start 276.00402 -292.777926)
		(end 275.742908 -292.516814)
		(width 0.20066)
		(layer "F.Cu")
		(net "M_C_CPU0_SA_DQS_DP<7>")
	)
	(segment
		(start 280.820368 -292.352984)
		(end 280.315416 -292.352984)
		(width 0.20066)
		(layer "F.Cu")
		(net "M_C_CPU0_SA_DQS_DP<7>")
	)
	(segment
		(start 277.390352 -292.08603)
		(end 277.120858 -292.355524)
		(width 0.20066)
		(layer "F.Cu")
		(net "M_C_CPU0_SA_DQS_DP<7>")
	)
	(segment
		(start 277.120858 -292.355524)
		(end 276.760686 -292.355524)
		(width 0.20066)
		(layer "F.Cu")
		(net "M_C_CPU0_SA_DQS_DP<7>")
	)
	(segment
		(start 283.916882 -292.516814)
		(end 282.811982 -292.516814)
		(width 0.20066)
		(layer "F.Cu")
		(net "M_C_CPU0_SA_DQS_DP<7>")
	)
	(segment
		(start 282.322016 -292.516814)
		(end 282.060904 -292.777926)
		(width 0.20066)
		(layer "F.Cu")
		(net "M_C_CPU0_SA_DQS_DP<7>")
	)
	(segment
		(start 275.742908 -292.516814)
		(end 275.268182 -292.516814)
		(width 0.20066)
		(layer "F.Cu")
		(net "M_C_CPU0_SA_DQS_DP<7>")
	)
	(segment
		(start 282.060904 -292.777926)
		(end 281.456384 -292.777926)
		(width 0.20066)
		(layer "F.Cu")
		(net "M_C_CPU0_SA_DQS_DP<7>")
	)
	(segment
		(start 276.760686 -292.355524)
		(end 276.338284 -292.777926)
		(width 0.20066)
		(layer "F.Cu")
		(net "M_C_CPU0_SA_DQS_DP<7>")
	)
	(segment
		(start 276.338284 -292.777926)
		(end 276.00402 -292.777926)
		(width 0.20066)
		(layer "F.Cu")
		(net "M_C_CPU0_SA_DQS_DP<7>")
	)
	(segment
		(start 325.115682 -273.196812)
		(end 324.727824 -273.58467)
		(width 0.18288)
		(layer "In4.Cu")
		(net "M_C_CPU0_SA_DQS_DP<7>")
	)
	(segment
		(start 293.183564 -291.769546)
		(end 292.186614 -291.769546)
		(width 0.18288)
		(layer "In4.Cu")
		(net "M_C_CPU0_SA_DQS_DP<7>")
	)
	(segment
		(start 339.767164 -267.26642)
		(end 339.759798 -267.262102)
		(width 0.088646)
		(layer "In4.Cu")
		(net "M_C_CPU0_SA_DQS_DP<7>")
	)
	(segment
		(start 319.791842 -278.34463)
		(end 319.40373 -278.732742)
		(width 0.18288)
		(layer "In4.Cu")
		(net "M_C_CPU0_SA_DQS_DP<7>")
	)
	(segment
		(start 326.067674 -272.068798)
		(end 326.067674 -272.24482)
		(width 0.18288)
		(layer "In4.Cu")
		(net "M_C_CPU0_SA_DQS_DP<7>")
	)
	(segment
		(start 313.652154 -286.782764)
		(end 313.446668 -286.987996)
		(width 0.18288)
		(layer "In4.Cu")
		(net "M_C_CPU0_SA_DQS_DP<7>")
	)
	(segment
		(start 329.487784 -268.82471)
		(end 329.311762 -268.82471)
		(width 0.18288)
		(layer "In4.Cu")
		(net "M_C_CPU0_SA_DQS_DP<7>")
	)
	(segment
		(start 328.35977 -269.776702)
		(end 327.971658 -270.164814)
		(width 0.18288)
		(layer "In4.Cu")
		(net "M_C_CPU0_SA_DQS_DP<7>")
	)
	(segment
		(start 323.59981 -274.536662)
		(end 323.211698 -274.924774)
		(width 0.18288)
		(layer "In4.Cu")
		(net "M_C_CPU0_SA_DQS_DP<7>")
	)
	(segment
		(start 327.5838 -270.728694)
		(end 327.407778 -270.728694)
		(width 0.18288)
		(layer "In4.Cu")
		(net "M_C_CPU0_SA_DQS_DP<7>")
	)
	(segment
		(start 311.577228 -287.517078)
		(end 310.71693 -288.377376)
		(width 0.18288)
		(layer "In4.Cu")
		(net "M_C_CPU0_SA_DQS_DP<7>")
	)
	(segment
		(start 334.503014 -267.265912)
		(end 334.503268 -267.266674)
		(width 0.088646)
		(layer "In4.Cu")
		(net "M_C_CPU0_SA_DQS_DP<7>")
	)
	(segment
		(start 320.355722 -277.78075)
		(end 320.355722 -277.956772)
		(width 0.18288)
		(layer "In4.Cu")
		(net "M_C_CPU0_SA_DQS_DP<7>")
	)
	(segment
		(start 323.775832 -274.536662)
		(end 323.59981 -274.536662)
		(width 0.18288)
		(layer "In4.Cu")
		(net "M_C_CPU0_SA_DQS_DP<7>")
	)
	(segment
		(start 298.812458 -291.241734)
		(end 298.549314 -291.504878)
		(width 0.18288)
		(layer "In4.Cu")
		(net "M_C_CPU0_SA_DQS_DP<7>")
	)
	(segment
		(start 338.831936 -267.26896)
		(end 338.827364 -267.26642)
		(width 0.088646)
		(layer "In4.Cu")
		(net "M_C_CPU0_SA_DQS_DP<7>")
	)
	(segment
		(start 314.84697 -285.769812)
		(end 314.569348 -285.88462)
		(width 0.18288)
		(layer "In4.Cu")
		(net "M_C_CPU0_SA_DQS_DP<7>")
	)
	(segment
		(start 324.551802 -273.58467)
		(end 324.16369 -273.972782)
		(width 0.18288)
		(layer "In4.Cu")
		(net "M_C_CPU0_SA_DQS_DP<7>")
	)
	(segment
		(start 331.646784 -268.56563)
		(end 331.51953 -268.56563)
		(width 0.088646)
		(layer "In4.Cu")
		(net "M_C_CPU0_SA_DQS_DP<7>")
	)
	(segment
		(start 295.093136 -292.091872)
		(end 294.708834 -292.091872)
		(width 0.18288)
		(layer "In4.Cu")
		(net "M_C_CPU0_SA_DQS_DP<7>")
	)
	(segment
		(start 326.631808 -271.680686)
		(end 326.455786 -271.680686)
		(width 0.18288)
		(layer "In4.Cu")
		(net "M_C_CPU0_SA_DQS_DP<7>")
	)
	(segment
		(start 329.806554 -268.50594)
		(end 329.487784 -268.82471)
		(width 0.18288)
		(layer "In4.Cu")
		(net "M_C_CPU0_SA_DQS_DP<7>")
	)
	(segment
		(start 328.92365 -269.212822)
		(end 328.92365 -269.388844)
		(width 0.18288)
		(layer "In4.Cu")
		(net "M_C_CPU0_SA_DQS_DP<7>")
	)
	(segment
		(start 314.569348 -285.88462)
		(end 314.325762 -286.128206)
		(width 0.18288)
		(layer "In4.Cu")
		(net "M_C_CPU0_SA_DQS_DP<7>")
	)
	(segment
		(start 314.325762 -286.128206)
		(end 313.907678 -286.128206)
		(width 0.18288)
		(layer "In4.Cu")
		(net "M_C_CPU0_SA_DQS_DP<7>")
	)
	(segment
		(start 300.430438 -291.513514)
		(end 299.464984 -291.513514)
		(width 0.18288)
		(layer "In4.Cu")
		(net "M_C_CPU0_SA_DQS_DP<7>")
	)
	(segment
		(start 317.057278 -283.57322)
		(end 314.870592 -285.759906)
		(width 0.18288)
		(layer "In4.Cu")
		(net "M_C_CPU0_SA_DQS_DP<7>")
	)
	(segment
		(start 304.172112 -292.105842)
		(end 303.798986 -292.105842)
		(width 0.18288)
		(layer "In4.Cu")
		(net "M_C_CPU0_SA_DQS_DP<7>")
	)
	(segment
		(start 324.16369 -273.972782)
		(end 324.16369 -274.148804)
		(width 0.18288)
		(layer "In4.Cu")
		(net "M_C_CPU0_SA_DQS_DP<7>")
	)
	(segment
		(start 338.827364 -267.26642)
		(end 338.819998 -267.262102)
		(width 0.088646)
		(layer "In4.Cu")
		(net "M_C_CPU0_SA_DQS_DP<7>")
	)
	(segment
		(start 339.771736 -267.26896)
		(end 339.767164 -267.26642)
		(width 0.088646)
		(layer "In4.Cu")
		(net "M_C_CPU0_SA_DQS_DP<7>")
	)
	(segment
		(start 328.535792 -269.776702)
		(end 328.35977 -269.776702)
		(width 0.18288)
		(layer "In4.Cu")
		(net "M_C_CPU0_SA_DQS_DP<7>")
	)
	(segment
		(start 320.355722 -277.956772)
		(end 319.967864 -278.34463)
		(width 0.18288)
		(layer "In4.Cu")
		(net "M_C_CPU0_SA_DQS_DP<7>")
	)
	(segment
		(start 310.71693 -288.377376)
		(end 309.136288 -288.377376)
		(width 0.18288)
		(layer "In4.Cu")
		(net "M_C_CPU0_SA_DQS_DP<7>")
	)
	(segment
		(start 292.186614 -291.769546)
		(end 291.69487 -292.26129)
		(width 0.18288)
		(layer "In4.Cu")
		(net "M_C_CPU0_SA_DQS_DP<7>")
	)
	(segment
		(start 327.971658 -270.164814)
		(end 327.971658 -270.340836)
		(width 0.18288)
		(layer "In4.Cu")
		(net "M_C_CPU0_SA_DQS_DP<7>")
	)
	(segment
		(start 332.905354 -267.190982)
		(end 332.52156 -267.190982)
		(width 0.088646)
		(layer "In4.Cu")
		(net "M_C_CPU0_SA_DQS_DP<7>")
	)
	(segment
		(start 289.244532 -292.26129)
		(end 287.338516 -293.05123)
		(width 0.18288)
		(layer "In4.Cu")
		(net "M_C_CPU0_SA_DQS_DP<7>")
	)
	(segment
		(start 287.338516 -293.05123)
		(end 284.966156 -293.05123)
		(width 0.18288)
		(layer "In4.Cu")
		(net "M_C_CPU0_SA_DQS_DP<7>")
	)
	(segment
		(start 299.464984 -291.513514)
		(end 299.193204 -291.241734)
		(width 0.18288)
		(layer "In4.Cu")
		(net "M_C_CPU0_SA_DQS_DP<7>")
	)
	(segment
		(start 321.307714 -277.00478)
		(end 320.919856 -277.392638)
		(width 0.18288)
		(layer "In4.Cu")
		(net "M_C_CPU0_SA_DQS_DP<7>")
	)
	(segment
		(start 284.190948 -292.79088)
		(end 283.916882 -292.516814)
		(width 0.18288)
		(layer "In4.Cu")
		(net "M_C_CPU0_SA_DQS_DP<7>")
	)
	(segment
		(start 303.798986 -292.105842)
		(end 302.977296 -291.765482)
		(width 0.18288)
		(layer "In4.Cu")
		(net "M_C_CPU0_SA_DQS_DP<7>")
	)
	(segment
		(start 314.846716 -285.769812)
		(end 314.84697 -285.769812)
		(width 0.18288)
		(layer "In4.Cu")
		(net "M_C_CPU0_SA_DQS_DP<7>")
	)
	(segment
		(start 297.893486 -291.504878)
		(end 297.032172 -292.366192)
		(width 0.18288)
		(layer "In4.Cu")
		(net "M_C_CPU0_SA_DQS_DP<7>")
	)
	(segment
		(start 298.549314 -291.504878)
		(end 297.893486 -291.504878)
		(width 0.18288)
		(layer "In4.Cu")
		(net "M_C_CPU0_SA_DQS_DP<7>")
	)
	(segment
		(start 291.69487 -292.26129)
		(end 289.244532 -292.26129)
		(width 0.18288)
		(layer "In4.Cu")
		(net "M_C_CPU0_SA_DQS_DP<7>")
	)
	(segment
		(start 326.455786 -271.680686)
		(end 326.067674 -272.068798)
		(width 0.18288)
		(layer "In4.Cu")
		(net "M_C_CPU0_SA_DQS_DP<7>")
	)
	(segment
		(start 295.367456 -292.366192)
		(end 295.093136 -292.091872)
		(width 0.18288)
		(layer "In4.Cu")
		(net "M_C_CPU0_SA_DQS_DP<7>")
	)
	(segment
		(start 321.695826 -276.440646)
		(end 321.307714 -276.828758)
		(width 0.18288)
		(layer "In4.Cu")
		(net "M_C_CPU0_SA_DQS_DP<7>")
	)
	(segment
		(start 294.443912 -292.356794)
		(end 293.770812 -292.356794)
		(width 0.18288)
		(layer "In4.Cu")
		(net "M_C_CPU0_SA_DQS_DP<7>")
	)
	(segment
		(start 327.407778 -270.728694)
		(end 327.019666 -271.116806)
		(width 0.18288)
		(layer "In4.Cu")
		(net "M_C_CPU0_SA_DQS_DP<7>")
	)
	(segment
		(start 312.170064 -287.517078)
		(end 311.577228 -287.517078)
		(width 0.18288)
		(layer "In4.Cu")
		(net "M_C_CPU0_SA_DQS_DP<7>")
	)
	(segment
		(start 327.019666 -271.116806)
		(end 327.019666 -271.292828)
		(width 0.18288)
		(layer "In4.Cu")
		(net "M_C_CPU0_SA_DQS_DP<7>")
	)
	(segment
		(start 284.966156 -293.05123)
		(end 284.705806 -292.79088)
		(width 0.18288)
		(layer "In4.Cu")
		(net "M_C_CPU0_SA_DQS_DP<7>")
	)
	(segment
		(start 322.647818 -275.488654)
		(end 322.259706 -275.876766)
		(width 0.18288)
		(layer "In4.Cu")
		(net "M_C_CPU0_SA_DQS_DP<7>")
	)
	(segment
		(start 309.136288 -288.377376)
		(end 306.592986 -290.920678)
		(width 0.18288)
		(layer "In4.Cu")
		(net "M_C_CPU0_SA_DQS_DP<7>")
	)
	(segment
		(start 325.679816 -272.632678)
		(end 325.503794 -272.632678)
		(width 0.18288)
		(layer "In4.Cu")
		(net "M_C_CPU0_SA_DQS_DP<7>")
	)
	(segment
		(start 294.708834 -292.091872)
		(end 294.443912 -292.356794)
		(width 0.18288)
		(layer "In4.Cu")
		(net "M_C_CPU0_SA_DQS_DP<7>")
	)
	(segment
		(start 313.652154 -286.38373)
		(end 313.652154 -286.782764)
		(width 0.18288)
		(layer "In4.Cu")
		(net "M_C_CPU0_SA_DQS_DP<7>")
	)
	(segment
		(start 329.311762 -268.82471)
		(end 328.92365 -269.212822)
		(width 0.18288)
		(layer "In4.Cu")
		(net "M_C_CPU0_SA_DQS_DP<7>")
	)
	(segment
		(start 331.436472 -268.50594)
		(end 329.806554 -268.50594)
		(width 0.18288)
		(layer "In4.Cu")
		(net "M_C_CPU0_SA_DQS_DP<7>")
	)
	(segment
		(start 321.307714 -276.828758)
		(end 321.307714 -277.00478)
		(width 0.18288)
		(layer "In4.Cu")
		(net "M_C_CPU0_SA_DQS_DP<7>")
	)
	(segment
		(start 293.770812 -292.356794)
		(end 293.183564 -291.769546)
		(width 0.18288)
		(layer "In4.Cu")
		(net "M_C_CPU0_SA_DQS_DP<7>")
	)
	(segment
		(start 336.951574 -267.268452)
		(end 336.947764 -267.266166)
		(width 0.088646)
		(layer "In4.Cu")
		(net "M_C_CPU0_SA_DQS_DP<7>")
	)
	(segment
		(start 331.51953 -268.56563)
		(end 331.45984 -268.50594)
		(width 0.088646)
		(layer "In4.Cu")
		(net "M_C_CPU0_SA_DQS_DP<7>")
	)
	(segment
		(start 313.446668 -286.987996)
		(end 312.170064 -287.517078)
		(width 0.18288)
		(layer "In4.Cu")
		(net "M_C_CPU0_SA_DQS_DP<7>")
	)
	(segment
		(start 284.705806 -292.79088)
		(end 284.190948 -292.79088)
		(width 0.18288)
		(layer "In4.Cu")
		(net "M_C_CPU0_SA_DQS_DP<7>")
	)
	(segment
		(start 328.92365 -269.388844)
		(end 328.535792 -269.776702)
		(width 0.18288)
		(layer "In4.Cu")
		(net "M_C_CPU0_SA_DQS_DP<7>")
	)
	(segment
		(start 323.211698 -275.100796)
		(end 322.82384 -275.488654)
		(width 0.18288)
		(layer "In4.Cu")
		(net "M_C_CPU0_SA_DQS_DP<7>")
	)
	(segment
		(start 299.193204 -291.241734)
		(end 298.812458 -291.241734)
		(width 0.18288)
		(layer "In4.Cu")
		(net "M_C_CPU0_SA_DQS_DP<7>")
	)
	(segment
		(start 325.115682 -273.02079)
		(end 325.115682 -273.196812)
		(width 0.18288)
		(layer "In4.Cu")
		(net "M_C_CPU0_SA_DQS_DP<7>")
	)
	(segment
		(start 321.871848 -276.440646)
		(end 321.695826 -276.440646)
		(width 0.18288)
		(layer "In4.Cu")
		(net "M_C_CPU0_SA_DQS_DP<7>")
	)
	(segment
		(start 320.743834 -277.392638)
		(end 320.355722 -277.78075)
		(width 0.18288)
		(layer "In4.Cu")
		(net "M_C_CPU0_SA_DQS_DP<7>")
	)
	(segment
		(start 319.40373 -278.732742)
		(end 319.40373 -278.908764)
		(width 0.18288)
		(layer "In4.Cu")
		(net "M_C_CPU0_SA_DQS_DP<7>")
	)
	(segment
		(start 324.16369 -274.148804)
		(end 323.775832 -274.536662)
		(width 0.18288)
		(layer "In4.Cu")
		(net "M_C_CPU0_SA_DQS_DP<7>")
	)
	(segment
		(start 301.039022 -291.765482)
		(end 300.430438 -291.513514)
		(width 0.18288)
		(layer "In4.Cu")
		(net "M_C_CPU0_SA_DQS_DP<7>")
	)
	(segment
		(start 340.740238 -267.284962)
		(end 340.706964 -267.26642)
		(width 0.088646)
		(layer "In4.Cu")
		(net "M_C_CPU0_SA_DQS_DP<7>")
	)
	(segment
		(start 327.019666 -271.292828)
		(end 326.631808 -271.680686)
		(width 0.18288)
		(layer "In4.Cu")
		(net "M_C_CPU0_SA_DQS_DP<7>")
	)
	(segment
		(start 332.52156 -267.190982)
		(end 331.73543 -267.977112)
		(width 0.088646)
		(layer "In4.Cu")
		(net "M_C_CPU0_SA_DQS_DP<7>")
	)
	(segment
		(start 340.706964 -267.26642)
		(end 340.699598 -267.262102)
		(width 0.088646)
		(layer "In4.Cu")
		(net "M_C_CPU0_SA_DQS_DP<7>")
	)
	(segment
		(start 326.067674 -272.24482)
		(end 325.679816 -272.632678)
		(width 0.18288)
		(layer "In4.Cu")
		(net "M_C_CPU0_SA_DQS_DP<7>")
	)
	(segment
		(start 331.45984 -268.50594)
		(end 331.436472 -268.50594)
		(width 0.088646)
		(layer "In4.Cu")
		(net "M_C_CPU0_SA_DQS_DP<7>")
	)
	(segment
		(start 319.967864 -278.34463)
		(end 319.791842 -278.34463)
		(width 0.18288)
		(layer "In4.Cu")
		(net "M_C_CPU0_SA_DQS_DP<7>")
	)
	(segment
		(start 327.971658 -270.340836)
		(end 327.5838 -270.728694)
		(width 0.18288)
		(layer "In4.Cu")
		(net "M_C_CPU0_SA_DQS_DP<7>")
	)
	(segment
		(start 302.977296 -291.765482)
		(end 301.039022 -291.765482)
		(width 0.18288)
		(layer "In4.Cu")
		(net "M_C_CPU0_SA_DQS_DP<7>")
	)
	(segment
		(start 314.870592 -285.759906)
		(end 314.846716 -285.769812)
		(width 0.18288)
		(layer "In4.Cu")
		(net "M_C_CPU0_SA_DQS_DP<7>")
	)
	(segment
		(start 337.890104 -267.267944)
		(end 337.887564 -267.26642)
		(width 0.088646)
		(layer "In4.Cu")
		(net "M_C_CPU0_SA_DQS_DP<7>")
	)
	(segment
		(start 320.919856 -277.392638)
		(end 320.743834 -277.392638)
		(width 0.18288)
		(layer "In4.Cu")
		(net "M_C_CPU0_SA_DQS_DP<7>")
	)
	(segment
		(start 331.73543 -267.977112)
		(end 331.73543 -268.476984)
		(width 0.088646)
		(layer "In4.Cu")
		(net "M_C_CPU0_SA_DQS_DP<7>")
	)
	(segment
		(start 297.032172 -292.366192)
		(end 295.367456 -292.366192)
		(width 0.18288)
		(layer "In4.Cu")
		(net "M_C_CPU0_SA_DQS_DP<7>")
	)
	(segment
		(start 322.259706 -276.052788)
		(end 321.871848 -276.440646)
		(width 0.18288)
		(layer "In4.Cu")
		(net "M_C_CPU0_SA_DQS_DP<7>")
	)
	(segment
		(start 318.695324 -279.616916)
		(end 317.057278 -283.57322)
		(width 0.18288)
		(layer "In4.Cu")
		(net "M_C_CPU0_SA_DQS_DP<7>")
	)
	(segment
		(start 322.82384 -275.488654)
		(end 322.647818 -275.488654)
		(width 0.18288)
		(layer "In4.Cu")
		(net "M_C_CPU0_SA_DQS_DP<7>")
	)
	(segment
		(start 313.907678 -286.128206)
		(end 313.652154 -286.38373)
		(width 0.18288)
		(layer "In4.Cu")
		(net "M_C_CPU0_SA_DQS_DP<7>")
	)
	(segment
		(start 325.503794 -272.632678)
		(end 325.115682 -273.02079)
		(width 0.18288)
		(layer "In4.Cu")
		(net "M_C_CPU0_SA_DQS_DP<7>")
	)
	(segment
		(start 319.40373 -278.908764)
		(end 318.695324 -279.616916)
		(width 0.18288)
		(layer "In4.Cu")
		(net "M_C_CPU0_SA_DQS_DP<7>")
	)
	(segment
		(start 306.592986 -290.920678)
		(end 305.087782 -291.726112)
		(width 0.18288)
		(layer "In4.Cu")
		(net "M_C_CPU0_SA_DQS_DP<7>")
	)
	(segment
		(start 331.73543 -268.476984)
		(end 331.646784 -268.56563)
		(width 0.088646)
		(layer "In4.Cu")
		(net "M_C_CPU0_SA_DQS_DP<7>")
	)
	(segment
		(start 305.087782 -291.726112)
		(end 304.172112 -292.105842)
		(width 0.18288)
		(layer "In4.Cu")
		(net "M_C_CPU0_SA_DQS_DP<7>")
	)
	(segment
		(start 323.211698 -274.924774)
		(end 323.211698 -275.100796)
		(width 0.18288)
		(layer "In4.Cu")
		(net "M_C_CPU0_SA_DQS_DP<7>")
	)
	(segment
		(start 324.727824 -273.58467)
		(end 324.551802 -273.58467)
		(width 0.18288)
		(layer "In4.Cu")
		(net "M_C_CPU0_SA_DQS_DP<7>")
	)
	(segment
		(start 322.259706 -275.876766)
		(end 322.259706 -276.052788)
		(width 0.18288)
		(layer "In4.Cu")
		(net "M_C_CPU0_SA_DQS_DP<7>")
	)
	(arc
		(start 340.141814 -267.26642)
		(mid 339.95712 -267.316521)
		(end 339.771736 -267.26896)
		(width 0.088646)
		(layer "In4.Cu")
		(net "M_C_CPU0_SA_DQS_DP<7>")
	)
	(arc
		(start 336.38236 -267.266166)
		(mid 336.195162 -267.316309)
		(end 336.007964 -267.266166)
		(width 0.088646)
		(layer "In4.Cu")
		(net "M_C_CPU0_SA_DQS_DP<7>")
	)
	(arc
		(start 335.44256 -267.266166)
		(mid 335.255362 -267.316309)
		(end 335.068164 -267.266166)
		(width 0.088646)
		(layer "In4.Cu")
		(net "M_C_CPU0_SA_DQS_DP<7>")
	)
	(arc
		(start 334.127856 -267.266674)
		(mid 333.845662 -267.191118)
		(end 333.563468 -267.266674)
		(width 0.088646)
		(layer "In4.Cu")
		(net "M_C_CPU0_SA_DQS_DP<7>")
	)
	(arc
		(start 334.503268 -267.266674)
		(mid 334.315562 -267.317003)
		(end 334.127856 -267.266674)
		(width 0.088646)
		(layer "In4.Cu")
		(net "M_C_CPU0_SA_DQS_DP<7>")
	)
	(arc
		(start 335.068164 -267.266166)
		(mid 334.785635 -267.190424)
		(end 334.503014 -267.265912)
		(width 0.088646)
		(layer "In4.Cu")
		(net "M_C_CPU0_SA_DQS_DP<7>")
	)
	(arc
		(start 333.563468 -267.266674)
		(mid 333.375762 -267.317003)
		(end 333.188056 -267.266674)
		(width 0.088646)
		(layer "In4.Cu")
		(net "M_C_CPU0_SA_DQS_DP<7>")
	)
	(arc
		(start 340.699598 -267.262102)
		(mid 340.420137 -267.190665)
		(end 340.141814 -267.26642)
		(width 0.088646)
		(layer "In4.Cu")
		(net "M_C_CPU0_SA_DQS_DP<7>")
	)
	(arc
		(start 337.887564 -267.26642)
		(mid 337.605006 -267.190771)
		(end 337.322414 -267.26642)
		(width 0.088646)
		(layer "In4.Cu")
		(net "M_C_CPU0_SA_DQS_DP<7>")
	)
	(arc
		(start 341.364062 -267.755878)
		(mid 341.068459 -267.498814)
		(end 340.740238 -267.284962)
		(width 0.088646)
		(layer "In4.Cu")
		(net "M_C_CPU0_SA_DQS_DP<7>")
	)
	(arc
		(start 339.202014 -267.26642)
		(mid 339.01732 -267.316521)
		(end 338.831936 -267.26896)
		(width 0.088646)
		(layer "In4.Cu")
		(net "M_C_CPU0_SA_DQS_DP<7>")
	)
	(arc
		(start 333.188056 -267.266674)
		(mid 333.051686 -267.210221)
		(end 332.905354 -267.190982)
		(width 0.088646)
		(layer "In4.Cu")
		(net "M_C_CPU0_SA_DQS_DP<7>")
	)
	(arc
		(start 338.819998 -267.262102)
		(mid 338.540537 -267.190665)
		(end 338.262214 -267.26642)
		(width 0.088646)
		(layer "In4.Cu")
		(net "M_C_CPU0_SA_DQS_DP<7>")
	)
	(arc
		(start 338.262214 -267.26642)
		(mid 338.076353 -267.316653)
		(end 337.890104 -267.267944)
		(width 0.088646)
		(layer "In4.Cu")
		(net "M_C_CPU0_SA_DQS_DP<7>")
	)
	(arc
		(start 336.007964 -267.266166)
		(mid 335.725262 -267.190424)
		(end 335.44256 -267.266166)
		(width 0.088646)
		(layer "In4.Cu")
		(net "M_C_CPU0_SA_DQS_DP<7>")
	)
	(arc
		(start 336.947764 -267.266166)
		(mid 336.665062 -267.190424)
		(end 336.38236 -267.266166)
		(width 0.088646)
		(layer "In4.Cu")
		(net "M_C_CPU0_SA_DQS_DP<7>")
	)
	(arc
		(start 339.759798 -267.262102)
		(mid 339.480337 -267.190665)
		(end 339.202014 -267.26642)
		(width 0.088646)
		(layer "In4.Cu")
		(net "M_C_CPU0_SA_DQS_DP<7>")
	)
	(arc
		(start 337.322414 -267.26642)
		(mid 337.137264 -267.316524)
		(end 336.951574 -267.268452)
		(width 0.088646)
		(layer "In4.Cu")
		(net "M_C_CPU0_SA_DQS_DP<7>")
	)
	(segment
		(start 277.390352 -301.436024)
		(end 277.120858 -301.705518)
		(width 0.20066)
		(layer "F.Cu")
		(net "M_C_CPU0_SA_DQS_DP<6>")
	)
	(segment
		(start 344.653362 -269.66164)
		(end 344.653616 -270.19758)
		(width 0.20066)
		(layer "F.Cu")
		(net "M_C_CPU0_SA_DQS_DP<6>")
	)
	(segment
		(start 276.760686 -301.705518)
		(end 276.338284 -302.12792)
		(width 0.20066)
		(layer "F.Cu")
		(net "M_C_CPU0_SA_DQS_DP<6>")
	)
	(segment
		(start 282.322016 -301.866808)
		(end 282.060904 -302.12792)
		(width 0.20066)
		(layer "F.Cu")
		(net "M_C_CPU0_SA_DQS_DP<6>")
	)
	(segment
		(start 280.315416 -301.702978)
		(end 280.054304 -301.441866)
		(width 0.20066)
		(layer "F.Cu")
		(net "M_C_CPU0_SA_DQS_DP<6>")
	)
	(segment
		(start 279.912826 -301.441866)
		(end 277.834344 -301.441866)
		(width 0.1016)
		(layer "F.Cu")
		(net "M_C_CPU0_SA_DQS_DP<6>")
	)
	(segment
		(start 275.742908 -301.866808)
		(end 275.268182 -301.866808)
		(width 0.20066)
		(layer "F.Cu")
		(net "M_C_CPU0_SA_DQS_DP<6>")
	)
	(segment
		(start 276.338284 -302.12792)
		(end 276.00402 -302.12792)
		(width 0.20066)
		(layer "F.Cu")
		(net "M_C_CPU0_SA_DQS_DP<6>")
	)
	(segment
		(start 283.916882 -301.866808)
		(end 282.811982 -301.866808)
		(width 0.20066)
		(layer "F.Cu")
		(net "M_C_CPU0_SA_DQS_DP<6>")
	)
	(segment
		(start 281.456384 -302.12792)
		(end 280.820368 -301.702978)
		(width 0.20066)
		(layer "F.Cu")
		(net "M_C_CPU0_SA_DQS_DP<6>")
	)
	(segment
		(start 277.120858 -301.705518)
		(end 276.760686 -301.705518)
		(width 0.20066)
		(layer "F.Cu")
		(net "M_C_CPU0_SA_DQS_DP<6>")
	)
	(segment
		(start 282.811982 -301.866808)
		(end 282.322016 -301.866808)
		(width 0.20066)
		(layer "F.Cu")
		(net "M_C_CPU0_SA_DQS_DP<6>")
	)
	(segment
		(start 276.00402 -302.12792)
		(end 275.742908 -301.866808)
		(width 0.20066)
		(layer "F.Cu")
		(net "M_C_CPU0_SA_DQS_DP<6>")
	)
	(segment
		(start 280.820368 -301.702978)
		(end 280.315416 -301.702978)
		(width 0.20066)
		(layer "F.Cu")
		(net "M_C_CPU0_SA_DQS_DP<6>")
	)
	(segment
		(start 282.060904 -302.12792)
		(end 281.456384 -302.12792)
		(width 0.20066)
		(layer "F.Cu")
		(net "M_C_CPU0_SA_DQS_DP<6>")
	)
	(segment
		(start 277.593552 -301.441866)
		(end 277.58771 -301.436024)
		(width 0.101854)
		(layer "F.Cu")
		(net "M_C_CPU0_SA_DQS_DP<6>")
	)
	(segment
		(start 277.834344 -301.441866)
		(end 277.593552 -301.441866)
		(width 0.101854)
		(layer "F.Cu")
		(net "M_C_CPU0_SA_DQS_DP<6>")
	)
	(segment
		(start 277.58771 -301.436024)
		(end 277.390352 -301.436024)
		(width 0.20066)
		(layer "F.Cu")
		(net "M_C_CPU0_SA_DQS_DP<6>")
	)
	(segment
		(start 280.054304 -301.441866)
		(end 279.912826 -301.441866)
		(width 0.20066)
		(layer "F.Cu")
		(net "M_C_CPU0_SA_DQS_DP<6>")
	)
	(segment
		(start 324.039484 -275.72081)
		(end 323.65188 -276.108668)
		(width 0.18288)
		(layer "In6.Cu")
		(net "M_C_CPU0_SA_DQS_DP<6>")
	)
	(segment
		(start 297.803316 -291.513768)
		(end 297.282616 -292.034214)
		(width 0.18288)
		(layer "In6.Cu")
		(net "M_C_CPU0_SA_DQS_DP<6>")
	)
	(segment
		(start 321.183762 -278.577548)
		(end 320.795904 -278.965406)
		(width 0.18288)
		(layer "In6.Cu")
		(net "M_C_CPU0_SA_DQS_DP<6>")
	)
	(segment
		(start 293.736014 -292.341046)
		(end 292.702996 -293.374064)
		(width 0.18288)
		(layer "In6.Cu")
		(net "M_C_CPU0_SA_DQS_DP<6>")
	)
	(segment
		(start 342.116664 -269.707868)
		(end 342.101932 -269.699232)
		(width 0.088646)
		(layer "In6.Cu")
		(net "M_C_CPU0_SA_DQS_DP<6>")
	)
	(segment
		(start 306.002944 -287.69818)
		(end 305.826922 -287.69818)
		(width 0.18288)
		(layer "In6.Cu")
		(net "M_C_CPU0_SA_DQS_DP<6>")
	)
	(segment
		(start 296.516044 -292.352222)
		(end 295.41597 -292.352222)
		(width 0.18288)
		(layer "In6.Cu")
		(net "M_C_CPU0_SA_DQS_DP<6>")
	)
	(segment
		(start 334.51165 -270.516858)
		(end 334.50276 -270.521938)
		(width 0.088646)
		(layer "In6.Cu")
		(net "M_C_CPU0_SA_DQS_DP<6>")
	)
	(segment
		(start 312.691526 -285.098236)
		(end 312.691526 -285.274258)
		(width 0.18288)
		(layer "In6.Cu")
		(net "M_C_CPU0_SA_DQS_DP<6>")
	)
	(segment
		(start 284.681676 -302.135032)
		(end 284.185106 -302.135032)
		(width 0.18288)
		(layer "In6.Cu")
		(net "M_C_CPU0_SA_DQS_DP<6>")
	)
	(segment
		(start 323.475604 -276.108668)
		(end 323.087492 -276.497034)
		(width 0.18288)
		(layer "In6.Cu")
		(net "M_C_CPU0_SA_DQS_DP<6>")
	)
	(segment
		(start 295.41597 -292.352222)
		(end 295.15562 -292.091872)
		(width 0.18288)
		(layer "In6.Cu")
		(net "M_C_CPU0_SA_DQS_DP<6>")
	)
	(segment
		(start 321.571874 -278.01316)
		(end 321.183762 -278.401526)
		(width 0.18288)
		(layer "In6.Cu")
		(net "M_C_CPU0_SA_DQS_DP<6>")
	)
	(segment
		(start 318.716152 -280.869898)
		(end 318.32804 -281.258264)
		(width 0.18288)
		(layer "In6.Cu")
		(net "M_C_CPU0_SA_DQS_DP<6>")
	)
	(segment
		(start 344.374216 -269.926562)
		(end 343.999312 -269.7099)
		(width 0.088646)
		(layer "In6.Cu")
		(net "M_C_CPU0_SA_DQS_DP<6>")
	)
	(segment
		(start 322.699888 -277.060914)
		(end 322.523866 -277.060914)
		(width 0.18288)
		(layer "In6.Cu")
		(net "M_C_CPU0_SA_DQS_DP<6>")
	)
	(segment
		(start 318.32804 -281.258264)
		(end 318.32804 -281.434286)
		(width 0.18288)
		(layer "In6.Cu")
		(net "M_C_CPU0_SA_DQS_DP<6>")
	)
	(segment
		(start 288.40303 -300.13148)
		(end 287.706816 -300.82744)
		(width 0.18288)
		(layer "In6.Cu")
		(net "M_C_CPU0_SA_DQS_DP<6>")
	)
	(segment
		(start 330.603098 -273.002248)
		(end 324.039484 -275.72081)
		(width 0.18288)
		(layer "In6.Cu")
		(net "M_C_CPU0_SA_DQS_DP<6>")
	)
	(segment
		(start 302.28032 -289.89274)
		(end 301.835058 -290.338002)
		(width 0.18288)
		(layer "In6.Cu")
		(net "M_C_CPU0_SA_DQS_DP<6>")
	)
	(segment
		(start 305.438556 -288.086546)
		(end 305.438556 -288.262568)
		(width 0.18288)
		(layer "In6.Cu")
		(net "M_C_CPU0_SA_DQS_DP<6>")
	)
	(segment
		(start 320.232024 -279.529794)
		(end 319.844166 -279.917652)
		(width 0.18288)
		(layer "In6.Cu")
		(net "M_C_CPU0_SA_DQS_DP<6>")
	)
	(segment
		(start 297.282616 -292.034214)
		(end 296.516044 -292.352222)
		(width 0.18288)
		(layer "In6.Cu")
		(net "M_C_CPU0_SA_DQS_DP<6>")
	)
	(segment
		(start 322.523866 -277.060914)
		(end 322.135754 -277.44928)
		(width 0.18288)
		(layer "In6.Cu")
		(net "M_C_CPU0_SA_DQS_DP<6>")
	)
	(segment
		(start 331.306424 -273.002248)
		(end 331.283056 -273.002248)
		(width 0.088646)
		(layer "In6.Cu")
		(net "M_C_CPU0_SA_DQS_DP<6>")
	)
	(segment
		(start 299.235876 -291.241734)
		(end 298.78147 -291.241734)
		(width 0.18288)
		(layer "In6.Cu")
		(net "M_C_CPU0_SA_DQS_DP<6>")
	)
	(segment
		(start 288.966656 -294.953182)
		(end 288.40303 -295.516808)
		(width 0.18288)
		(layer "In6.Cu")
		(net "M_C_CPU0_SA_DQS_DP<6>")
	)
	(segment
		(start 318.32804 -281.434286)
		(end 317.940182 -281.822144)
		(width 0.18288)
		(layer "In6.Cu")
		(net "M_C_CPU0_SA_DQS_DP<6>")
	)
	(segment
		(start 307.435504 -286.652208)
		(end 306.979574 -286.84093)
		(width 0.18288)
		(layer "In6.Cu")
		(net "M_C_CPU0_SA_DQS_DP<6>")
	)
	(segment
		(start 295.15562 -292.091872)
		(end 294.681402 -292.091872)
		(width 0.18288)
		(layer "In6.Cu")
		(net "M_C_CPU0_SA_DQS_DP<6>")
	)
	(segment
		(start 285.324804 -302.330104)
		(end 284.876748 -302.330104)
		(width 0.18288)
		(layer "In6.Cu")
		(net "M_C_CPU0_SA_DQS_DP<6>")
	)
	(segment
		(start 317.76416 -281.822144)
		(end 317.376048 -282.21051)
		(width 0.18288)
		(layer "In6.Cu")
		(net "M_C_CPU0_SA_DQS_DP<6>")
	)
	(segment
		(start 339.682328 -269.701772)
		(end 339.671914 -269.707868)
		(width 0.088646)
		(layer "In6.Cu")
		(net "M_C_CPU0_SA_DQS_DP<6>")
	)
	(segment
		(start 332.178914 -271.833594)
		(end 332.178914 -272.060162)
		(width 0.088646)
		(layer "In6.Cu")
		(net "M_C_CPU0_SA_DQS_DP<6>")
	)
	(segment
		(start 313.079638 -284.710124)
		(end 312.691526 -285.098236)
		(width 0.18288)
		(layer "In6.Cu")
		(net "M_C_CPU0_SA_DQS_DP<6>")
	)
	(segment
		(start 320.619882 -278.965406)
		(end 320.23177 -279.353772)
		(width 0.18288)
		(layer "In6.Cu")
		(net "M_C_CPU0_SA_DQS_DP<6>")
	)
	(segment
		(start 313.895994 -284.06979)
		(end 313.25566 -284.710124)
		(width 0.18288)
		(layer "In6.Cu")
		(net "M_C_CPU0_SA_DQS_DP<6>")
	)
	(segment
		(start 286.205168 -301.449486)
		(end 285.324804 -302.330104)
		(width 0.18288)
		(layer "In6.Cu")
		(net "M_C_CPU0_SA_DQS_DP<6>")
	)
	(segment
		(start 321.747896 -278.01316)
		(end 321.571874 -278.01316)
		(width 0.18288)
		(layer "In6.Cu")
		(net "M_C_CPU0_SA_DQS_DP<6>")
	)
	(segment
		(start 317.376048 -282.21051)
		(end 317.376302 -282.386532)
		(width 0.18288)
		(layer "In6.Cu")
		(net "M_C_CPU0_SA_DQS_DP<6>")
	)
	(segment
		(start 331.564234 -273.061938)
		(end 331.366114 -273.061938)
		(width 0.088646)
		(layer "In6.Cu")
		(net "M_C_CPU0_SA_DQS_DP<6>")
	)
	(segment
		(start 323.087492 -276.497034)
		(end 323.087746 -276.673056)
		(width 0.18288)
		(layer "In6.Cu")
		(net "M_C_CPU0_SA_DQS_DP<6>")
	)
	(segment
		(start 341.176864 -269.707868)
		(end 341.162132 -269.699232)
		(width 0.088646)
		(layer "In6.Cu")
		(net "M_C_CPU0_SA_DQS_DP<6>")
	)
	(segment
		(start 301.835058 -290.338002)
		(end 301.659036 -290.338256)
		(width 0.18288)
		(layer "In6.Cu")
		(net "M_C_CPU0_SA_DQS_DP<6>")
	)
	(segment
		(start 323.087746 -276.673056)
		(end 322.699888 -277.060914)
		(width 0.18288)
		(layer "In6.Cu")
		(net "M_C_CPU0_SA_DQS_DP<6>")
	)
	(segment
		(start 319.668144 -279.917652)
		(end 319.280032 -280.306018)
		(width 0.18288)
		(layer "In6.Cu")
		(net "M_C_CPU0_SA_DQS_DP<6>")
	)
	(segment
		(start 322.135754 -277.44928)
		(end 322.135754 -277.625302)
		(width 0.18288)
		(layer "In6.Cu")
		(net "M_C_CPU0_SA_DQS_DP<6>")
	)
	(segment
		(start 331.283056 -273.002248)
		(end 330.603098 -273.002248)
		(width 0.18288)
		(layer "In6.Cu")
		(net "M_C_CPU0_SA_DQS_DP<6>")
	)
	(segment
		(start 311.101232 -285.662116)
		(end 310.11114 -286.652208)
		(width 0.18288)
		(layer "In6.Cu")
		(net "M_C_CPU0_SA_DQS_DP<6>")
	)
	(segment
		(start 298.509436 -291.513768)
		(end 297.803316 -291.513768)
		(width 0.18288)
		(layer "In6.Cu")
		(net "M_C_CPU0_SA_DQS_DP<6>")
	)
	(segment
		(start 303.144174 -289.399726)
		(end 303.076864 -289.562794)
		(width 0.18288)
		(layer "In6.Cu")
		(net "M_C_CPU0_SA_DQS_DP<6>")
	)
	(segment
		(start 312.303668 -285.662116)
		(end 311.101232 -285.662116)
		(width 0.18288)
		(layer "In6.Cu")
		(net "M_C_CPU0_SA_DQS_DP<6>")
	)
	(segment
		(start 316.988444 -282.77439)
		(end 316.812422 -282.77439)
		(width 0.18288)
		(layer "In6.Cu")
		(net "M_C_CPU0_SA_DQS_DP<6>")
	)
	(segment
		(start 331.732636 -272.893536)
		(end 331.564234 -273.061938)
		(width 0.088646)
		(layer "In6.Cu")
		(net "M_C_CPU0_SA_DQS_DP<6>")
	)
	(segment
		(start 294.432228 -292.341046)
		(end 293.736014 -292.341046)
		(width 0.18288)
		(layer "In6.Cu")
		(net "M_C_CPU0_SA_DQS_DP<6>")
	)
	(segment
		(start 343.43086 -269.708122)
		(end 343.43086 -269.707868)
		(width 0.088646)
		(layer "In6.Cu")
		(net "M_C_CPU0_SA_DQS_DP<6>")
	)
	(segment
		(start 317.940182 -281.822144)
		(end 317.76416 -281.822144)
		(width 0.18288)
		(layer "In6.Cu")
		(net "M_C_CPU0_SA_DQS_DP<6>")
	)
	(segment
		(start 320.23177 -279.353772)
		(end 320.232024 -279.529794)
		(width 0.18288)
		(layer "In6.Cu")
		(net "M_C_CPU0_SA_DQS_DP<6>")
	)
	(segment
		(start 343.99855 -269.709392)
		(end 343.981532 -269.699486)
		(width 0.088646)
		(layer "In6.Cu")
		(net "M_C_CPU0_SA_DQS_DP<6>")
	)
	(segment
		(start 319.844166 -279.917652)
		(end 319.668144 -279.917652)
		(width 0.18288)
		(layer "In6.Cu")
		(net "M_C_CPU0_SA_DQS_DP<6>")
	)
	(segment
		(start 288.40303 -295.516808)
		(end 288.40303 -300.13148)
		(width 0.18288)
		(layer "In6.Cu")
		(net "M_C_CPU0_SA_DQS_DP<6>")
	)
	(segment
		(start 289.51682 -294.953182)
		(end 288.966656 -294.953182)
		(width 0.18288)
		(layer "In6.Cu")
		(net "M_C_CPU0_SA_DQS_DP<6>")
	)
	(segment
		(start 343.999312 -269.7099)
		(end 343.99855 -269.709392)
		(width 0.088646)
		(layer "In6.Cu")
		(net "M_C_CPU0_SA_DQS_DP<6>")
	)
	(segment
		(start 301.270924 -290.90239)
		(end 300.67123 -291.502084)
		(width 0.18288)
		(layer "In6.Cu")
		(net "M_C_CPU0_SA_DQS_DP<6>")
	)
	(segment
		(start 331.732636 -272.50644)
		(end 331.732636 -272.893536)
		(width 0.088646)
		(layer "In6.Cu")
		(net "M_C_CPU0_SA_DQS_DP<6>")
	)
	(segment
		(start 316.42431 -283.338778)
		(end 315.693552 -284.06979)
		(width 0.18288)
		(layer "In6.Cu")
		(net "M_C_CPU0_SA_DQS_DP<6>")
	)
	(segment
		(start 292.702996 -293.374064)
		(end 291.095938 -293.374064)
		(width 0.18288)
		(layer "In6.Cu")
		(net "M_C_CPU0_SA_DQS_DP<6>")
	)
	(segment
		(start 344.653616 -270.19758)
		(end 344.374216 -269.926562)
		(width 0.088646)
		(layer "In6.Cu")
		(net "M_C_CPU0_SA_DQS_DP<6>")
	)
	(segment
		(start 333.280512 -271.00149)
		(end 333.280512 -271.011396)
		(width 0.088646)
		(layer "In6.Cu")
		(net "M_C_CPU0_SA_DQS_DP<6>")
	)
	(segment
		(start 319.280032 -280.306018)
		(end 319.280032 -280.48204)
		(width 0.18288)
		(layer "In6.Cu")
		(net "M_C_CPU0_SA_DQS_DP<6>")
	)
	(segment
		(start 310.11114 -286.652208)
		(end 307.435504 -286.652208)
		(width 0.18288)
		(layer "In6.Cu")
		(net "M_C_CPU0_SA_DQS_DP<6>")
	)
	(segment
		(start 343.056464 -269.707868)
		(end 343.041732 -269.699232)
		(width 0.088646)
		(layer "In6.Cu")
		(net "M_C_CPU0_SA_DQS_DP<6>")
	)
	(segment
		(start 317.376302 -282.386532)
		(end 316.988444 -282.77439)
		(width 0.18288)
		(layer "In6.Cu")
		(net "M_C_CPU0_SA_DQS_DP<6>")
	)
	(segment
		(start 301.659036 -290.338256)
		(end 301.270924 -290.726368)
		(width 0.18288)
		(layer "In6.Cu")
		(net "M_C_CPU0_SA_DQS_DP<6>")
	)
	(segment
		(start 284.185106 -302.135032)
		(end 283.916882 -301.866808)
		(width 0.18288)
		(layer "In6.Cu")
		(net "M_C_CPU0_SA_DQS_DP<6>")
	)
	(segment
		(start 316.812422 -282.77439)
		(end 316.42431 -283.162756)
		(width 0.18288)
		(layer "In6.Cu")
		(net "M_C_CPU0_SA_DQS_DP<6>")
	)
	(segment
		(start 298.78147 -291.241734)
		(end 298.509436 -291.513768)
		(width 0.18288)
		(layer "In6.Cu")
		(net "M_C_CPU0_SA_DQS_DP<6>")
	)
	(segment
		(start 305.438556 -288.262568)
		(end 304.889916 -288.811208)
		(width 0.18288)
		(layer "In6.Cu")
		(net "M_C_CPU0_SA_DQS_DP<6>")
	)
	(segment
		(start 334.690212 -270.179038)
		(end 334.690212 -270.19758)
		(width 0.088646)
		(layer "In6.Cu")
		(net "M_C_CPU0_SA_DQS_DP<6>")
	)
	(segment
		(start 312.691526 -285.274258)
		(end 312.303668 -285.662116)
		(width 0.18288)
		(layer "In6.Cu")
		(net "M_C_CPU0_SA_DQS_DP<6>")
	)
	(segment
		(start 318.892174 -280.869898)
		(end 318.716152 -280.869898)
		(width 0.18288)
		(layer "In6.Cu")
		(net "M_C_CPU0_SA_DQS_DP<6>")
	)
	(segment
		(start 284.876748 -302.330104)
		(end 284.681676 -302.135032)
		(width 0.18288)
		(layer "In6.Cu")
		(net "M_C_CPU0_SA_DQS_DP<6>")
	)
	(segment
		(start 304.889916 -288.811208)
		(end 303.813972 -289.256978)
		(width 0.18288)
		(layer "In6.Cu")
		(net "M_C_CPU0_SA_DQS_DP<6>")
	)
	(segment
		(start 305.826922 -287.69818)
		(end 305.438556 -288.086546)
		(width 0.18288)
		(layer "In6.Cu")
		(net "M_C_CPU0_SA_DQS_DP<6>")
	)
	(segment
		(start 315.693552 -284.06979)
		(end 313.895994 -284.06979)
		(width 0.18288)
		(layer "In6.Cu")
		(net "M_C_CPU0_SA_DQS_DP<6>")
	)
	(segment
		(start 322.135754 -277.625302)
		(end 321.747896 -278.01316)
		(width 0.18288)
		(layer "In6.Cu")
		(net "M_C_CPU0_SA_DQS_DP<6>")
	)
	(segment
		(start 339.297518 -269.707868)
		(end 339.287104 -269.701772)
		(width 0.088646)
		(layer "In6.Cu")
		(net "M_C_CPU0_SA_DQS_DP<6>")
	)
	(segment
		(start 291.095938 -293.374064)
		(end 289.51682 -294.953182)
		(width 0.18288)
		(layer "In6.Cu")
		(net "M_C_CPU0_SA_DQS_DP<6>")
	)
	(segment
		(start 301.270924 -290.726368)
		(end 301.270924 -290.90239)
		(width 0.18288)
		(layer "In6.Cu")
		(net "M_C_CPU0_SA_DQS_DP<6>")
	)
	(segment
		(start 321.183762 -278.401526)
		(end 321.183762 -278.577548)
		(width 0.18288)
		(layer "In6.Cu")
		(net "M_C_CPU0_SA_DQS_DP<6>")
	)
	(segment
		(start 287.706816 -300.82744)
		(end 286.205168 -301.449486)
		(width 0.18288)
		(layer "In6.Cu")
		(net "M_C_CPU0_SA_DQS_DP<6>")
	)
	(segment
		(start 323.65188 -276.108668)
		(end 323.475604 -276.108668)
		(width 0.18288)
		(layer "In6.Cu")
		(net "M_C_CPU0_SA_DQS_DP<6>")
	)
	(segment
		(start 332.906116 -271.3863)
		(end 332.626208 -271.3863)
		(width 0.088646)
		(layer "In6.Cu")
		(net "M_C_CPU0_SA_DQS_DP<6>")
	)
	(segment
		(start 300.67123 -291.502084)
		(end 299.496226 -291.502084)
		(width 0.18288)
		(layer "In6.Cu")
		(net "M_C_CPU0_SA_DQS_DP<6>")
	)
	(segment
		(start 320.795904 -278.965406)
		(end 320.619882 -278.965406)
		(width 0.18288)
		(layer "In6.Cu")
		(net "M_C_CPU0_SA_DQS_DP<6>")
	)
	(segment
		(start 299.496226 -291.502084)
		(end 299.235876 -291.241734)
		(width 0.18288)
		(layer "In6.Cu")
		(net "M_C_CPU0_SA_DQS_DP<6>")
	)
	(segment
		(start 332.178914 -272.060162)
		(end 331.732636 -272.50644)
		(width 0.088646)
		(layer "In6.Cu")
		(net "M_C_CPU0_SA_DQS_DP<6>")
	)
	(segment
		(start 316.42431 -283.162756)
		(end 316.42431 -283.338778)
		(width 0.18288)
		(layer "In6.Cu")
		(net "M_C_CPU0_SA_DQS_DP<6>")
	)
	(segment
		(start 306.619402 -287.081722)
		(end 306.002944 -287.69818)
		(width 0.18288)
		(layer "In6.Cu")
		(net "M_C_CPU0_SA_DQS_DP<6>")
	)
	(segment
		(start 303.813972 -289.256978)
		(end 303.651158 -289.189668)
		(width 0.18288)
		(layer "In6.Cu")
		(net "M_C_CPU0_SA_DQS_DP<6>")
	)
	(segment
		(start 294.681402 -292.091872)
		(end 294.432228 -292.341046)
		(width 0.18288)
		(layer "In6.Cu")
		(net "M_C_CPU0_SA_DQS_DP<6>")
	)
	(segment
		(start 306.979574 -286.84093)
		(end 306.619402 -287.081722)
		(width 0.18288)
		(layer "In6.Cu")
		(net "M_C_CPU0_SA_DQS_DP<6>")
	)
	(segment
		(start 332.626208 -271.3863)
		(end 332.178914 -271.833594)
		(width 0.088646)
		(layer "In6.Cu")
		(net "M_C_CPU0_SA_DQS_DP<6>")
	)
	(segment
		(start 331.366114 -273.061938)
		(end 331.306424 -273.002248)
		(width 0.088646)
		(layer "In6.Cu")
		(net "M_C_CPU0_SA_DQS_DP<6>")
	)
	(segment
		(start 303.076864 -289.562794)
		(end 302.28032 -289.89274)
		(width 0.18288)
		(layer "In6.Cu")
		(net "M_C_CPU0_SA_DQS_DP<6>")
	)
	(segment
		(start 313.25566 -284.710124)
		(end 313.079638 -284.710124)
		(width 0.18288)
		(layer "In6.Cu")
		(net "M_C_CPU0_SA_DQS_DP<6>")
	)
	(segment
		(start 319.280032 -280.48204)
		(end 318.892174 -280.869898)
		(width 0.18288)
		(layer "In6.Cu")
		(net "M_C_CPU0_SA_DQS_DP<6>")
	)
	(segment
		(start 303.651158 -289.189668)
		(end 303.144174 -289.399726)
		(width 0.18288)
		(layer "In6.Cu")
		(net "M_C_CPU0_SA_DQS_DP<6>")
	)
	(arc
		(start 339.671914 -269.707868)
		(mid 339.484716 -269.758011)
		(end 339.297518 -269.707868)
		(width 0.088646)
		(layer "In6.Cu")
		(net "M_C_CPU0_SA_DQS_DP<6>")
	)
	(arc
		(start 343.041732 -269.699232)
		(mid 342.765291 -269.632066)
		(end 342.49106 -269.707868)
		(width 0.088646)
		(layer "In6.Cu")
		(net "M_C_CPU0_SA_DQS_DP<6>")
	)
	(arc
		(start 337.417664 -269.707868)
		(mid 337.134962 -269.632126)
		(end 336.85226 -269.707868)
		(width 0.088646)
		(layer "In6.Cu")
		(net "M_C_CPU0_SA_DQS_DP<6>")
	)
	(arc
		(start 334.128364 -270.521938)
		(mid 333.845662 -270.446162)
		(end 333.56296 -270.521938)
		(width 0.088646)
		(layer "In6.Cu")
		(net "M_C_CPU0_SA_DQS_DP<6>")
	)
	(arc
		(start 334.50276 -270.521938)
		(mid 334.315562 -270.572081)
		(end 334.128364 -270.521938)
		(width 0.088646)
		(layer "In6.Cu")
		(net "M_C_CPU0_SA_DQS_DP<6>")
	)
	(arc
		(start 338.73186 -269.707868)
		(mid 338.544662 -269.758011)
		(end 338.357464 -269.707868)
		(width 0.088646)
		(layer "In6.Cu")
		(net "M_C_CPU0_SA_DQS_DP<6>")
	)
	(arc
		(start 335.91246 -269.707868)
		(mid 335.725262 -269.758011)
		(end 335.538064 -269.707868)
		(width 0.088646)
		(layer "In6.Cu")
		(net "M_C_CPU0_SA_DQS_DP<6>")
	)
	(arc
		(start 336.85226 -269.707868)
		(mid 336.665062 -269.758011)
		(end 336.477864 -269.707868)
		(width 0.088646)
		(layer "In6.Cu")
		(net "M_C_CPU0_SA_DQS_DP<6>")
	)
	(arc
		(start 340.237064 -269.707868)
		(mid 339.960505 -269.632159)
		(end 339.682328 -269.701772)
		(width 0.088646)
		(layer "In6.Cu")
		(net "M_C_CPU0_SA_DQS_DP<6>")
	)
	(arc
		(start 333.56296 -270.521938)
		(mid 333.358625 -270.724543)
		(end 333.280512 -271.00149)
		(width 0.088646)
		(layer "In6.Cu")
		(net "M_C_CPU0_SA_DQS_DP<6>")
	)
	(arc
		(start 343.981532 -269.699486)
		(mid 343.705057 -269.632166)
		(end 343.43086 -269.708122)
		(width 0.088646)
		(layer "In6.Cu")
		(net "M_C_CPU0_SA_DQS_DP<6>")
	)
	(arc
		(start 343.43086 -269.707868)
		(mid 343.243662 -269.758011)
		(end 343.056464 -269.707868)
		(width 0.088646)
		(layer "In6.Cu")
		(net "M_C_CPU0_SA_DQS_DP<6>")
	)
	(arc
		(start 334.690212 -270.19758)
		(mid 334.642533 -270.38048)
		(end 334.51165 -270.516858)
		(width 0.088646)
		(layer "In6.Cu")
		(net "M_C_CPU0_SA_DQS_DP<6>")
	)
	(arc
		(start 336.477864 -269.707868)
		(mid 336.195162 -269.632126)
		(end 335.91246 -269.707868)
		(width 0.088646)
		(layer "In6.Cu")
		(net "M_C_CPU0_SA_DQS_DP<6>")
	)
	(arc
		(start 337.79206 -269.707868)
		(mid 337.604862 -269.758011)
		(end 337.417664 -269.707868)
		(width 0.088646)
		(layer "In6.Cu")
		(net "M_C_CPU0_SA_DQS_DP<6>")
	)
	(arc
		(start 334.97266 -269.707868)
		(mid 334.770374 -269.906849)
		(end 334.690212 -270.179038)
		(width 0.088646)
		(layer "In6.Cu")
		(net "M_C_CPU0_SA_DQS_DP<6>")
	)
	(arc
		(start 339.287104 -269.701772)
		(mid 339.008672 -269.631958)
		(end 338.73186 -269.707868)
		(width 0.088646)
		(layer "In6.Cu")
		(net "M_C_CPU0_SA_DQS_DP<6>")
	)
	(arc
		(start 341.55126 -269.707868)
		(mid 341.364062 -269.758011)
		(end 341.176864 -269.707868)
		(width 0.088646)
		(layer "In6.Cu")
		(net "M_C_CPU0_SA_DQS_DP<6>")
	)
	(arc
		(start 335.538064 -269.707868)
		(mid 335.255362 -269.632126)
		(end 334.97266 -269.707868)
		(width 0.088646)
		(layer "In6.Cu")
		(net "M_C_CPU0_SA_DQS_DP<6>")
	)
	(arc
		(start 341.162132 -269.699232)
		(mid 340.885691 -269.632066)
		(end 340.61146 -269.707868)
		(width 0.088646)
		(layer "In6.Cu")
		(net "M_C_CPU0_SA_DQS_DP<6>")
	)
	(arc
		(start 342.101932 -269.699232)
		(mid 341.825491 -269.632066)
		(end 341.55126 -269.707868)
		(width 0.088646)
		(layer "In6.Cu")
		(net "M_C_CPU0_SA_DQS_DP<6>")
	)
	(arc
		(start 338.357464 -269.707868)
		(mid 338.074762 -269.632126)
		(end 337.79206 -269.707868)
		(width 0.088646)
		(layer "In6.Cu")
		(net "M_C_CPU0_SA_DQS_DP<6>")
	)
	(arc
		(start 342.49106 -269.707868)
		(mid 342.303862 -269.758011)
		(end 342.116664 -269.707868)
		(width 0.088646)
		(layer "In6.Cu")
		(net "M_C_CPU0_SA_DQS_DP<6>")
	)
	(arc
		(start 333.280512 -271.011396)
		(mid 333.170885 -271.276313)
		(end 332.906116 -271.3863)
		(width 0.088646)
		(layer "In6.Cu")
		(net "M_C_CPU0_SA_DQS_DP<6>")
	)
	(arc
		(start 340.61146 -269.707868)
		(mid 340.424262 -269.758011)
		(end 340.237064 -269.707868)
		(width 0.088646)
		(layer "In6.Cu")
		(net "M_C_CPU0_SA_DQS_DP<6>")
	)
	(segment
		(start 280.820368 -311.052972)
		(end 280.315416 -311.052972)
		(width 0.20066)
		(layer "F.Cu")
		(net "M_C_CPU0_SA_DQS_DP<5>")
	)
	(segment
		(start 277.593552 -310.79186)
		(end 277.58771 -310.786018)
		(width 0.101854)
		(layer "F.Cu")
		(net "M_C_CPU0_SA_DQS_DP<5>")
	)
	(segment
		(start 277.58771 -310.786018)
		(end 277.390352 -310.786018)
		(width 0.20066)
		(layer "F.Cu")
		(net "M_C_CPU0_SA_DQS_DP<5>")
	)
	(segment
		(start 276.760686 -311.055512)
		(end 276.338284 -311.477914)
		(width 0.20066)
		(layer "F.Cu")
		(net "M_C_CPU0_SA_DQS_DP<5>")
	)
	(segment
		(start 277.390352 -310.786018)
		(end 277.120858 -311.055512)
		(width 0.20066)
		(layer "F.Cu")
		(net "M_C_CPU0_SA_DQS_DP<5>")
	)
	(segment
		(start 276.338284 -311.477914)
		(end 276.00402 -311.477914)
		(width 0.20066)
		(layer "F.Cu")
		(net "M_C_CPU0_SA_DQS_DP<5>")
	)
	(segment
		(start 282.060904 -311.477914)
		(end 281.456384 -311.477914)
		(width 0.20066)
		(layer "F.Cu")
		(net "M_C_CPU0_SA_DQS_DP<5>")
	)
	(segment
		(start 282.322016 -311.216802)
		(end 282.060904 -311.477914)
		(width 0.20066)
		(layer "F.Cu")
		(net "M_C_CPU0_SA_DQS_DP<5>")
	)
	(segment
		(start 280.054304 -310.79186)
		(end 279.912826 -310.79186)
		(width 0.20066)
		(layer "F.Cu")
		(net "M_C_CPU0_SA_DQS_DP<5>")
	)
	(segment
		(start 282.811982 -311.216802)
		(end 282.322016 -311.216802)
		(width 0.20066)
		(layer "F.Cu")
		(net "M_C_CPU0_SA_DQS_DP<5>")
	)
	(segment
		(start 279.912826 -310.79186)
		(end 277.834344 -310.79186)
		(width 0.1016)
		(layer "F.Cu")
		(net "M_C_CPU0_SA_DQS_DP<5>")
	)
	(segment
		(start 277.120858 -311.055512)
		(end 276.760686 -311.055512)
		(width 0.20066)
		(layer "F.Cu")
		(net "M_C_CPU0_SA_DQS_DP<5>")
	)
	(segment
		(start 275.742908 -311.216802)
		(end 275.268182 -311.216802)
		(width 0.20066)
		(layer "F.Cu")
		(net "M_C_CPU0_SA_DQS_DP<5>")
	)
	(segment
		(start 281.456384 -311.477914)
		(end 280.820368 -311.052972)
		(width 0.20066)
		(layer "F.Cu")
		(net "M_C_CPU0_SA_DQS_DP<5>")
	)
	(segment
		(start 342.304116 -276.986492)
		(end 342.303862 -276.986746)
		(width 0.20066)
		(layer "F.Cu")
		(net "M_C_CPU0_SA_DQS_DP<5>")
	)
	(segment
		(start 277.834344 -310.79186)
		(end 277.593552 -310.79186)
		(width 0.101854)
		(layer "F.Cu")
		(net "M_C_CPU0_SA_DQS_DP<5>")
	)
	(segment
		(start 276.00402 -311.477914)
		(end 275.742908 -311.216802)
		(width 0.20066)
		(layer "F.Cu")
		(net "M_C_CPU0_SA_DQS_DP<5>")
	)
	(segment
		(start 342.303862 -276.986746)
		(end 342.303862 -277.522432)
		(width 0.20066)
		(layer "F.Cu")
		(net "M_C_CPU0_SA_DQS_DP<5>")
	)
	(segment
		(start 283.916882 -311.216802)
		(end 282.811982 -311.216802)
		(width 0.20066)
		(layer "F.Cu")
		(net "M_C_CPU0_SA_DQS_DP<5>")
	)
	(segment
		(start 280.315416 -311.052972)
		(end 280.054304 -310.79186)
		(width 0.20066)
		(layer "F.Cu")
		(net "M_C_CPU0_SA_DQS_DP<5>")
	)
	(segment
		(start 336.86115 -281.097482)
		(end 336.847434 -281.105356)
		(width 0.088646)
		(layer "In4.Cu")
		(net "M_C_CPU0_SA_DQS_DP<5>")
	)
	(segment
		(start 329.423268 -287.712658)
		(end 325.778876 -296.509186)
		(width 0.18288)
		(layer "In4.Cu")
		(net "M_C_CPU0_SA_DQS_DP<5>")
	)
	(segment
		(start 332.454758 -284.681168)
		(end 332.433422 -284.702504)
		(width 0.088646)
		(layer "In4.Cu")
		(net "M_C_CPU0_SA_DQS_DP<5>")
	)
	(segment
		(start 341.991188 -277.522432)
		(end 341.925656 -277.4569)
		(width 0.088646)
		(layer "In4.Cu")
		(net "M_C_CPU0_SA_DQS_DP<5>")
	)
	(segment
		(start 333.280512 -283.760418)
		(end 332.822042 -284.218888)
		(width 0.088646)
		(layer "In4.Cu")
		(net "M_C_CPU0_SA_DQS_DP<5>")
	)
	(segment
		(start 337.509612 -278.31796)
		(end 337.509612 -278.336502)
		(width 0.088646)
		(layer "In4.Cu")
		(net "M_C_CPU0_SA_DQS_DP<5>")
	)
	(segment
		(start 292.66896 -312.760614)
		(end 292.010592 -312.102246)
		(width 0.18288)
		(layer "In4.Cu")
		(net "M_C_CPU0_SA_DQS_DP<5>")
	)
	(segment
		(start 336.853022 -279.474168)
		(end 336.85226 -279.474676)
		(width 0.088646)
		(layer "In4.Cu")
		(net "M_C_CPU0_SA_DQS_DP<5>")
	)
	(segment
		(start 335.453228 -281.910282)
		(end 335.436718 -281.919934)
		(width 0.088646)
		(layer "In4.Cu")
		(net "M_C_CPU0_SA_DQS_DP<5>")
	)
	(segment
		(start 310.814466 -310.484266)
		(end 307.19141 -310.484266)
		(width 0.18288)
		(layer "In4.Cu")
		(net "M_C_CPU0_SA_DQS_DP<5>")
	)
	(segment
		(start 292.010592 -312.102246)
		(end 289.518598 -312.102246)
		(width 0.18288)
		(layer "In4.Cu")
		(net "M_C_CPU0_SA_DQS_DP<5>")
	)
	(segment
		(start 318.523366 -304.90795)
		(end 312.53811 -310.893206)
		(width 0.18288)
		(layer "In4.Cu")
		(net "M_C_CPU0_SA_DQS_DP<5>")
	)
	(segment
		(start 337.039712 -279.140412)
		(end 337.039712 -279.150318)
		(width 0.088646)
		(layer "In4.Cu")
		(net "M_C_CPU0_SA_DQS_DP<5>")
	)
	(segment
		(start 294.710612 -313.341766)
		(end 294.45331 -313.599068)
		(width 0.18288)
		(layer "In4.Cu")
		(net "M_C_CPU0_SA_DQS_DP<5>")
	)
	(segment
		(start 289.234118 -311.817766)
		(end 284.91053 -311.817766)
		(width 0.18288)
		(layer "In4.Cu")
		(net "M_C_CPU0_SA_DQS_DP<5>")
	)
	(segment
		(start 333.750412 -283.201364)
		(end 333.750412 -283.219906)
		(width 0.088646)
		(layer "In4.Cu")
		(net "M_C_CPU0_SA_DQS_DP<5>")
	)
	(segment
		(start 312.53811 -310.893206)
		(end 311.223406 -310.893206)
		(width 0.18288)
		(layer "In4.Cu")
		(net "M_C_CPU0_SA_DQS_DP<5>")
	)
	(segment
		(start 340.156546 -277.024338)
		(end 340.141814 -277.032974)
		(width 0.088646)
		(layer "In4.Cu")
		(net "M_C_CPU0_SA_DQS_DP<5>")
	)
	(segment
		(start 299.175932 -312.491628)
		(end 298.812204 -312.491628)
		(width 0.18288)
		(layer "In4.Cu")
		(net "M_C_CPU0_SA_DQS_DP<5>")
	)
	(segment
		(start 299.442124 -312.75782)
		(end 299.175932 -312.491628)
		(width 0.18288)
		(layer "In4.Cu")
		(net "M_C_CPU0_SA_DQS_DP<5>")
	)
	(segment
		(start 302.99152 -312.75782)
		(end 299.442124 -312.75782)
		(width 0.18288)
		(layer "In4.Cu")
		(net "M_C_CPU0_SA_DQS_DP<5>")
	)
	(segment
		(start 304.328322 -311.421018)
		(end 302.99152 -312.75782)
		(width 0.18288)
		(layer "In4.Cu")
		(net "M_C_CPU0_SA_DQS_DP<5>")
	)
	(segment
		(start 298.812204 -312.491628)
		(end 298.557696 -312.746136)
		(width 0.18288)
		(layer "In4.Cu")
		(net "M_C_CPU0_SA_DQS_DP<5>")
	)
	(segment
		(start 325.778876 -296.509186)
		(end 318.523366 -303.764696)
		(width 0.18288)
		(layer "In4.Cu")
		(net "M_C_CPU0_SA_DQS_DP<5>")
	)
	(segment
		(start 341.096346 -277.024338)
		(end 341.081614 -277.032974)
		(width 0.088646)
		(layer "In4.Cu")
		(net "M_C_CPU0_SA_DQS_DP<5>")
	)
	(segment
		(start 336.85226 -280.453846)
		(end 336.86115 -280.458926)
		(width 0.088646)
		(layer "In4.Cu")
		(net "M_C_CPU0_SA_DQS_DP<5>")
	)
	(segment
		(start 311.223406 -310.893206)
		(end 310.814466 -310.484266)
		(width 0.18288)
		(layer "In4.Cu")
		(net "M_C_CPU0_SA_DQS_DP<5>")
	)
	(segment
		(start 294.45331 -313.599068)
		(end 293.959026 -313.599068)
		(width 0.18288)
		(layer "In4.Cu")
		(net "M_C_CPU0_SA_DQS_DP<5>")
	)
	(segment
		(start 298.557696 -312.746136)
		(end 297.72991 -312.746136)
		(width 0.18288)
		(layer "In4.Cu")
		(net "M_C_CPU0_SA_DQS_DP<5>")
	)
	(segment
		(start 293.959026 -313.599068)
		(end 293.120572 -312.760614)
		(width 0.18288)
		(layer "In4.Cu")
		(net "M_C_CPU0_SA_DQS_DP<5>")
	)
	(segment
		(start 295.353232 -313.619134)
		(end 295.075864 -313.341766)
		(width 0.18288)
		(layer "In4.Cu")
		(net "M_C_CPU0_SA_DQS_DP<5>")
	)
	(segment
		(start 306.836064 -310.839104)
		(end 305.430936 -311.421018)
		(width 0.18288)
		(layer "In4.Cu")
		(net "M_C_CPU0_SA_DQS_DP<5>")
	)
	(segment
		(start 338.827364 -277.032974)
		(end 338.812632 -277.024338)
		(width 0.088646)
		(layer "In4.Cu")
		(net "M_C_CPU0_SA_DQS_DP<5>")
	)
	(segment
		(start 336.847434 -281.105356)
		(end 336.846164 -281.106118)
		(width 0.088646)
		(layer "In4.Cu")
		(net "M_C_CPU0_SA_DQS_DP<5>")
	)
	(segment
		(start 332.538832 -284.681168)
		(end 332.454758 -284.681168)
		(width 0.088646)
		(layer "In4.Cu")
		(net "M_C_CPU0_SA_DQS_DP<5>")
	)
	(segment
		(start 307.19141 -310.484266)
		(end 306.836064 -310.839104)
		(width 0.18288)
		(layer "In4.Cu")
		(net "M_C_CPU0_SA_DQS_DP<5>")
	)
	(segment
		(start 333.750412 -283.226256)
		(end 333.750666 -283.22651)
		(width 0.088646)
		(layer "In4.Cu")
		(net "M_C_CPU0_SA_DQS_DP<5>")
	)
	(segment
		(start 336.86115 -279.469596)
		(end 336.853022 -279.474168)
		(width 0.088646)
		(layer "In4.Cu")
		(net "M_C_CPU0_SA_DQS_DP<5>")
	)
	(segment
		(start 332.822042 -284.218888)
		(end 332.695296 -284.524704)
		(width 0.088646)
		(layer "In4.Cu")
		(net "M_C_CPU0_SA_DQS_DP<5>")
	)
	(segment
		(start 284.577028 -311.484264)
		(end 284.184344 -311.484264)
		(width 0.18288)
		(layer "In4.Cu")
		(net "M_C_CPU0_SA_DQS_DP<5>")
	)
	(segment
		(start 293.120572 -312.760614)
		(end 292.66896 -312.760614)
		(width 0.18288)
		(layer "In4.Cu")
		(net "M_C_CPU0_SA_DQS_DP<5>")
	)
	(segment
		(start 337.33105 -278.65578)
		(end 337.32216 -278.66086)
		(width 0.088646)
		(layer "In4.Cu")
		(net "M_C_CPU0_SA_DQS_DP<5>")
	)
	(segment
		(start 297.72991 -312.746136)
		(end 296.856912 -313.619134)
		(width 0.18288)
		(layer "In4.Cu")
		(net "M_C_CPU0_SA_DQS_DP<5>")
	)
	(segment
		(start 296.856912 -313.619134)
		(end 295.353232 -313.619134)
		(width 0.18288)
		(layer "In4.Cu")
		(net "M_C_CPU0_SA_DQS_DP<5>")
	)
	(segment
		(start 339.212174 -277.026878)
		(end 339.20176 -277.032974)
		(width 0.088646)
		(layer "In4.Cu")
		(net "M_C_CPU0_SA_DQS_DP<5>")
	)
	(segment
		(start 332.695296 -284.524704)
		(end 332.538832 -284.681168)
		(width 0.088646)
		(layer "In4.Cu")
		(net "M_C_CPU0_SA_DQS_DP<5>")
	)
	(segment
		(start 289.518598 -312.102246)
		(end 289.234118 -311.817766)
		(width 0.18288)
		(layer "In4.Cu")
		(net "M_C_CPU0_SA_DQS_DP<5>")
	)
	(segment
		(start 335.160112 -282.405836)
		(end 335.160112 -282.414472)
		(width 0.088646)
		(layer "In4.Cu")
		(net "M_C_CPU0_SA_DQS_DP<5>")
	)
	(segment
		(start 318.523366 -303.764696)
		(end 318.523366 -304.90795)
		(width 0.18288)
		(layer "In4.Cu")
		(net "M_C_CPU0_SA_DQS_DP<5>")
	)
	(segment
		(start 284.91053 -311.817766)
		(end 284.577028 -311.484264)
		(width 0.18288)
		(layer "In4.Cu")
		(net "M_C_CPU0_SA_DQS_DP<5>")
	)
	(segment
		(start 337.80095 -277.84171)
		(end 337.79206 -277.84679)
		(width 0.088646)
		(layer "In4.Cu")
		(net "M_C_CPU0_SA_DQS_DP<5>")
	)
	(segment
		(start 295.075864 -313.341766)
		(end 294.710612 -313.341766)
		(width 0.18288)
		(layer "In4.Cu")
		(net "M_C_CPU0_SA_DQS_DP<5>")
	)
	(segment
		(start 284.184344 -311.484264)
		(end 283.916882 -311.216802)
		(width 0.18288)
		(layer "In4.Cu")
		(net "M_C_CPU0_SA_DQS_DP<5>")
	)
	(segment
		(start 305.430936 -311.421018)
		(end 304.328322 -311.421018)
		(width 0.18288)
		(layer "In4.Cu")
		(net "M_C_CPU0_SA_DQS_DP<5>")
	)
	(segment
		(start 342.303862 -277.522432)
		(end 341.991188 -277.522432)
		(width 0.088646)
		(layer "In4.Cu")
		(net "M_C_CPU0_SA_DQS_DP<5>")
	)
	(segment
		(start 332.433422 -284.702504)
		(end 329.423268 -287.712658)
		(width 0.18288)
		(layer "In4.Cu")
		(net "M_C_CPU0_SA_DQS_DP<5>")
	)
	(arc
		(start 333.750666 -283.22651)
		(mid 333.698977 -283.409981)
		(end 333.563722 -283.544264)
		(width 0.088646)
		(layer "In4.Cu")
		(net "M_C_CPU0_SA_DQS_DP<5>")
	)
	(arc
		(start 337.039458 -280.766012)
		(mid 337.039625 -280.777188)
		(end 337.039458 -280.788364)
		(width 0.088646)
		(layer "In4.Cu")
		(net "M_C_CPU0_SA_DQS_DP<5>")
	)
	(arc
		(start 337.32216 -278.66086)
		(mid 337.117825 -278.863465)
		(end 337.039712 -279.140412)
		(width 0.088646)
		(layer "In4.Cu")
		(net "M_C_CPU0_SA_DQS_DP<5>")
	)
	(arc
		(start 335.436718 -281.919934)
		(mid 335.234131 -282.126285)
		(end 335.160112 -282.405836)
		(width 0.088646)
		(layer "In4.Cu")
		(net "M_C_CPU0_SA_DQS_DP<5>")
	)
	(arc
		(start 340.141814 -277.032974)
		(mid 339.954616 -277.083117)
		(end 339.767418 -277.032974)
		(width 0.088646)
		(layer "In4.Cu")
		(net "M_C_CPU0_SA_DQS_DP<5>")
	)
	(arc
		(start 334.598518 -282.730194)
		(mid 334.040925 -282.725481)
		(end 333.750412 -283.201364)
		(width 0.088646)
		(layer "In4.Cu")
		(net "M_C_CPU0_SA_DQS_DP<5>")
	)
	(arc
		(start 336.846164 -281.106118)
		(mid 336.643751 -281.312531)
		(end 336.569812 -281.59202)
		(width 0.088646)
		(layer "In4.Cu")
		(net "M_C_CPU0_SA_DQS_DP<5>")
	)
	(arc
		(start 336.569812 -281.59202)
		(mid 336.382513 -281.916461)
		(end 336.007964 -281.916378)
		(width 0.088646)
		(layer "In4.Cu")
		(net "M_C_CPU0_SA_DQS_DP<5>")
	)
	(arc
		(start 341.925656 -277.4569)
		(mid 341.924358 -277.446346)
		(end 341.922862 -277.435818)
		(width 0.088646)
		(layer "In4.Cu")
		(net "M_C_CPU0_SA_DQS_DP<5>")
	)
	(arc
		(start 341.922862 -277.435818)
		(mid 341.830701 -277.203046)
		(end 341.647018 -277.032974)
		(width 0.088646)
		(layer "In4.Cu")
		(net "M_C_CPU0_SA_DQS_DP<5>")
	)
	(arc
		(start 341.647018 -277.032974)
		(mid 341.372819 -276.957139)
		(end 341.096346 -277.024338)
		(width 0.088646)
		(layer "In4.Cu")
		(net "M_C_CPU0_SA_DQS_DP<5>")
	)
	(arc
		(start 338.812632 -277.024338)
		(mid 338.532628 -276.957084)
		(end 338.255864 -277.03653)
		(width 0.088646)
		(layer "In4.Cu")
		(net "M_C_CPU0_SA_DQS_DP<5>")
	)
	(arc
		(start 338.255864 -277.03653)
		(mid 338.053451 -277.242943)
		(end 337.979512 -277.522432)
		(width 0.088646)
		(layer "In4.Cu")
		(net "M_C_CPU0_SA_DQS_DP<5>")
	)
	(arc
		(start 339.20176 -277.032974)
		(mid 339.014562 -277.083117)
		(end 338.827364 -277.032974)
		(width 0.088646)
		(layer "In4.Cu")
		(net "M_C_CPU0_SA_DQS_DP<5>")
	)
	(arc
		(start 333.563722 -283.544264)
		(mid 333.414886 -283.642867)
		(end 333.280512 -283.760418)
		(width 0.088646)
		(layer "In4.Cu")
		(net "M_C_CPU0_SA_DQS_DP<5>")
	)
	(arc
		(start 336.85226 -279.474676)
		(mid 336.569508 -279.964324)
		(end 336.85226 -280.453846)
		(width 0.088646)
		(layer "In4.Cu")
		(net "M_C_CPU0_SA_DQS_DP<5>")
	)
	(arc
		(start 341.081614 -277.032974)
		(mid 340.894416 -277.083117)
		(end 340.707218 -277.032974)
		(width 0.088646)
		(layer "In4.Cu")
		(net "M_C_CPU0_SA_DQS_DP<5>")
	)
	(arc
		(start 336.007964 -281.916378)
		(mid 335.731405 -281.840635)
		(end 335.453228 -281.910282)
		(width 0.088646)
		(layer "In4.Cu")
		(net "M_C_CPU0_SA_DQS_DP<5>")
	)
	(arc
		(start 337.509612 -278.336502)
		(mid 337.461933 -278.519402)
		(end 337.33105 -278.65578)
		(width 0.088646)
		(layer "In4.Cu")
		(net "M_C_CPU0_SA_DQS_DP<5>")
	)
	(arc
		(start 335.160112 -282.414472)
		(mid 334.969238 -282.732281)
		(end 334.598518 -282.730194)
		(width 0.088646)
		(layer "In4.Cu")
		(net "M_C_CPU0_SA_DQS_DP<5>")
	)
	(arc
		(start 337.79206 -277.84679)
		(mid 337.589774 -278.045771)
		(end 337.509612 -278.31796)
		(width 0.088646)
		(layer "In4.Cu")
		(net "M_C_CPU0_SA_DQS_DP<5>")
	)
	(arc
		(start 339.767418 -277.032974)
		(mid 339.490605 -276.957104)
		(end 339.212174 -277.026878)
		(width 0.088646)
		(layer "In4.Cu")
		(net "M_C_CPU0_SA_DQS_DP<5>")
	)
	(arc
		(start 340.707218 -277.032974)
		(mid 340.433019 -276.957139)
		(end 340.156546 -277.024338)
		(width 0.088646)
		(layer "In4.Cu")
		(net "M_C_CPU0_SA_DQS_DP<5>")
	)
	(arc
		(start 337.039712 -279.150318)
		(mid 336.992033 -279.333218)
		(end 336.86115 -279.469596)
		(width 0.088646)
		(layer "In4.Cu")
		(net "M_C_CPU0_SA_DQS_DP<5>")
	)
	(arc
		(start 337.039458 -280.788364)
		(mid 336.989443 -280.965495)
		(end 336.86115 -281.097482)
		(width 0.088646)
		(layer "In4.Cu")
		(net "M_C_CPU0_SA_DQS_DP<5>")
	)
	(arc
		(start 333.750412 -283.219906)
		(mid 333.750427 -283.223081)
		(end 333.750412 -283.226256)
		(width 0.088646)
		(layer "In4.Cu")
		(net "M_C_CPU0_SA_DQS_DP<5>")
	)
	(arc
		(start 337.979512 -277.522432)
		(mid 337.931833 -277.705332)
		(end 337.80095 -277.84171)
		(width 0.088646)
		(layer "In4.Cu")
		(net "M_C_CPU0_SA_DQS_DP<5>")
	)
	(arc
		(start 336.86115 -280.458926)
		(mid 336.988961 -280.590019)
		(end 337.039458 -280.766012)
		(width 0.088646)
		(layer "In4.Cu")
		(net "M_C_CPU0_SA_DQS_DP<5>")
	)
	(segment
		(start 271.967198 -275.255482)
		(end 271.706086 -275.516594)
		(width 0.20066)
		(layer "F.Cu")
		(net "M_C_CPU0_SA_DQS_DP<4>")
	)
	(segment
		(start 276.145752 -275.94179)
		(end 274.390358 -275.94179)
		(width 0.1016)
		(layer "F.Cu")
		(net "M_C_CPU0_SA_DQS_DP<4>")
	)
	(segment
		(start 278.711914 -275.516594)
		(end 278.163274 -275.516594)
		(width 0.20066)
		(layer "F.Cu")
		(net "M_C_CPU0_SA_DQS_DP<4>")
	)
	(segment
		(start 278.163274 -275.516594)
		(end 277.902162 -275.255482)
		(width 0.20066)
		(layer "F.Cu")
		(net "M_C_CPU0_SA_DQS_DP<4>")
	)
	(segment
		(start 277.208234 -275.680678)
		(end 276.882352 -275.680678)
		(width 0.20066)
		(layer "F.Cu")
		(net "M_C_CPU0_SA_DQS_DP<4>")
	)
	(segment
		(start 279.816814 -275.516594)
		(end 278.711914 -275.516594)
		(width 0.20066)
		(layer "F.Cu")
		(net "M_C_CPU0_SA_DQS_DP<4>")
	)
	(segment
		(start 276.882352 -275.680678)
		(end 276.62124 -275.94179)
		(width 0.20066)
		(layer "F.Cu")
		(net "M_C_CPU0_SA_DQS_DP<4>")
	)
	(segment
		(start 273.028156 -275.680678)
		(end 272.39214 -275.255482)
		(width 0.20066)
		(layer "F.Cu")
		(net "M_C_CPU0_SA_DQS_DP<4>")
	)
	(segment
		(start 273.916394 -275.94179)
		(end 273.655282 -275.680678)
		(width 0.20066)
		(layer "F.Cu")
		(net "M_C_CPU0_SA_DQS_DP<4>")
	)
	(segment
		(start 342.773762 -260.430518)
		(end 342.773508 -260.430772)
		(width 0.20066)
		(layer "F.Cu")
		(net "M_C_CPU0_SA_DQS_DP<4>")
	)
	(segment
		(start 271.706086 -275.516594)
		(end 271.168114 -275.516594)
		(width 0.20066)
		(layer "F.Cu")
		(net "M_C_CPU0_SA_DQS_DP<4>")
	)
	(segment
		(start 274.014184 -275.94179)
		(end 273.916394 -275.94179)
		(width 0.20066)
		(layer "F.Cu")
		(net "M_C_CPU0_SA_DQS_DP<4>")
	)
	(segment
		(start 273.655282 -275.680678)
		(end 273.028156 -275.680678)
		(width 0.20066)
		(layer "F.Cu")
		(net "M_C_CPU0_SA_DQS_DP<4>")
	)
	(segment
		(start 274.390358 -275.94179)
		(end 274.014184 -275.94179)
		(width 0.101854)
		(layer "F.Cu")
		(net "M_C_CPU0_SA_DQS_DP<4>")
	)
	(segment
		(start 276.53488 -275.94179)
		(end 276.145752 -275.94179)
		(width 0.101854)
		(layer "F.Cu")
		(net "M_C_CPU0_SA_DQS_DP<4>")
	)
	(segment
		(start 272.39214 -275.255482)
		(end 271.967198 -275.255482)
		(width 0.20066)
		(layer "F.Cu")
		(net "M_C_CPU0_SA_DQS_DP<4>")
	)
	(segment
		(start 277.902162 -275.255482)
		(end 277.63343 -275.255482)
		(width 0.20066)
		(layer "F.Cu")
		(net "M_C_CPU0_SA_DQS_DP<4>")
	)
	(segment
		(start 276.62124 -275.94179)
		(end 276.53488 -275.94179)
		(width 0.20066)
		(layer "F.Cu")
		(net "M_C_CPU0_SA_DQS_DP<4>")
	)
	(segment
		(start 342.773762 -259.894832)
		(end 342.773762 -260.430518)
		(width 0.20066)
		(layer "F.Cu")
		(net "M_C_CPU0_SA_DQS_DP<4>")
	)
	(segment
		(start 277.63343 -275.255482)
		(end 277.208234 -275.680678)
		(width 0.20066)
		(layer "F.Cu")
		(net "M_C_CPU0_SA_DQS_DP<4>")
	)
	(segment
		(start 342.54821 -260.251956)
		(end 342.274652 -260.251956)
		(width 0.088646)
		(layer "In6.Cu")
		(net "M_C_CPU0_SA_DQS_DP<4>")
	)
	(segment
		(start 306.700936 -265.691366)
		(end 305.939444 -265.691366)
		(width 0.18288)
		(layer "In6.Cu")
		(net "M_C_CPU0_SA_DQS_DP<4>")
	)
	(segment
		(start 308.219094 -266.095226)
		(end 307.67528 -266.095226)
		(width 0.18288)
		(layer "In6.Cu")
		(net "M_C_CPU0_SA_DQS_DP<4>")
	)
	(segment
		(start 305.141884 -265.691366)
		(end 304.242216 -265.691366)
		(width 0.18288)
		(layer "In6.Cu")
		(net "M_C_CPU0_SA_DQS_DP<4>")
	)
	(segment
		(start 297.854116 -266.307062)
		(end 297.00601 -267.155168)
		(width 0.18288)
		(layer "In6.Cu")
		(net "M_C_CPU0_SA_DQS_DP<4>")
	)
	(segment
		(start 294.4114 -267.146024)
		(end 294.037512 -267.146024)
		(width 0.18288)
		(layer "In6.Cu")
		(net "M_C_CPU0_SA_DQS_DP<4>")
	)
	(segment
		(start 342.773508 -260.430772)
		(end 342.741758 -260.314948)
		(width 0.088646)
		(layer "In6.Cu")
		(net "M_C_CPU0_SA_DQS_DP<4>")
	)
	(segment
		(start 294.422576 -267.1572)
		(end 294.4114 -267.146024)
		(width 0.18288)
		(layer "In6.Cu")
		(net "M_C_CPU0_SA_DQS_DP<4>")
	)
	(segment
		(start 288.409888 -270.993616)
		(end 288.342578 -271.15643)
		(width 0.18288)
		(layer "In6.Cu")
		(net "M_C_CPU0_SA_DQS_DP<4>")
	)
	(segment
		(start 293.547038 -267.62329)
		(end 293.090854 -267.928344)
		(width 0.18288)
		(layer "In6.Cu")
		(net "M_C_CPU0_SA_DQS_DP<4>")
	)
	(segment
		(start 291.5285 -268.822678)
		(end 290.979606 -269.371572)
		(width 0.18288)
		(layer "In6.Cu")
		(net "M_C_CPU0_SA_DQS_DP<4>")
	)
	(segment
		(start 301.385986 -266.316714)
		(end 299.54728 -266.316714)
		(width 0.18288)
		(layer "In6.Cu")
		(net "M_C_CPU0_SA_DQS_DP<4>")
	)
	(segment
		(start 294.430704 -267.1572)
		(end 294.422576 -267.1572)
		(width 0.18288)
		(layer "In6.Cu")
		(net "M_C_CPU0_SA_DQS_DP<4>")
	)
	(segment
		(start 301.510446 -266.441174)
		(end 301.385986 -266.316714)
		(width 0.18288)
		(layer "In6.Cu")
		(net "M_C_CPU0_SA_DQS_DP<4>")
	)
	(segment
		(start 337.337146 -260.11505)
		(end 337.322414 -260.106414)
		(width 0.088646)
		(layer "In6.Cu")
		(net "M_C_CPU0_SA_DQS_DP<4>")
	)
	(segment
		(start 330.621386 -261.082028)
		(end 330.598018 -261.082028)
		(width 0.088646)
		(layer "In6.Cu")
		(net "M_C_CPU0_SA_DQS_DP<4>")
	)
	(segment
		(start 318.472058 -262.375396)
		(end 317.923418 -262.375396)
		(width 0.18288)
		(layer "In6.Cu")
		(net "M_C_CPU0_SA_DQS_DP<4>")
	)
	(segment
		(start 295.171876 -267.442188)
		(end 294.715692 -267.442188)
		(width 0.18288)
		(layer "In6.Cu")
		(net "M_C_CPU0_SA_DQS_DP<4>")
	)
	(segment
		(start 305.939444 -265.691366)
		(end 305.814984 -265.815826)
		(width 0.18288)
		(layer "In6.Cu")
		(net "M_C_CPU0_SA_DQS_DP<4>")
	)
	(segment
		(start 342.741758 -260.314948)
		(end 342.702896 -260.29285)
		(width 0.088646)
		(layer "In6.Cu")
		(net "M_C_CPU0_SA_DQS_DP<4>")
	)
	(segment
		(start 284.183582 -273.392392)
		(end 283.689806 -273.392392)
		(width 0.18288)
		(layer "In6.Cu")
		(net "M_C_CPU0_SA_DQS_DP<4>")
	)
	(segment
		(start 317.923418 -262.375396)
		(end 317.416434 -262.584946)
		(width 0.18288)
		(layer "In6.Cu")
		(net "M_C_CPU0_SA_DQS_DP<4>")
	)
	(segment
		(start 288.342578 -271.15643)
		(end 287.83534 -271.366488)
		(width 0.18288)
		(layer "In6.Cu")
		(net "M_C_CPU0_SA_DQS_DP<4>")
	)
	(segment
		(start 305.814984 -265.815826)
		(end 305.266344 -265.815826)
		(width 0.18288)
		(layer "In6.Cu")
		(net "M_C_CPU0_SA_DQS_DP<4>")
	)
	(segment
		(start 287.83534 -271.366488)
		(end 287.67278 -271.299178)
		(width 0.18288)
		(layer "In6.Cu")
		(net "M_C_CPU0_SA_DQS_DP<4>")
	)
	(segment
		(start 280.089102 -275.244306)
		(end 279.816814 -275.516594)
		(width 0.18288)
		(layer "In6.Cu")
		(net "M_C_CPU0_SA_DQS_DP<4>")
	)
	(segment
		(start 316.104778 -263.26211)
		(end 315.597286 -263.47166)
		(width 0.18288)
		(layer "In6.Cu")
		(net "M_C_CPU0_SA_DQS_DP<4>")
	)
	(segment
		(start 317.349124 -262.74776)
		(end 316.841632 -262.95731)
		(width 0.18288)
		(layer "In6.Cu")
		(net "M_C_CPU0_SA_DQS_DP<4>")
	)
	(segment
		(start 292.918134 -267.894054)
		(end 291.5285 -268.822678)
		(width 0.18288)
		(layer "In6.Cu")
		(net "M_C_CPU0_SA_DQS_DP<4>")
	)
	(segment
		(start 342.021414 -260.10616)
		(end 342.02116 -260.106414)
		(width 0.088646)
		(layer "In6.Cu")
		(net "M_C_CPU0_SA_DQS_DP<4>")
	)
	(segment
		(start 304.242216 -265.691366)
		(end 302.732186 -266.316714)
		(width 0.18288)
		(layer "In6.Cu")
		(net "M_C_CPU0_SA_DQS_DP<4>")
	)
	(segment
		(start 317.416434 -262.584946)
		(end 317.349124 -262.74776)
		(width 0.18288)
		(layer "In6.Cu")
		(net "M_C_CPU0_SA_DQS_DP<4>")
	)
	(segment
		(start 314.35294 -263.98601)
		(end 314.19038 -263.918446)
		(width 0.18288)
		(layer "In6.Cu")
		(net "M_C_CPU0_SA_DQS_DP<4>")
	)
	(segment
		(start 283.053028 -273.103086)
		(end 280.911808 -275.244306)
		(width 0.18288)
		(layer "In6.Cu")
		(net "M_C_CPU0_SA_DQS_DP<4>")
	)
	(segment
		(start 298.530772 -266.307062)
		(end 297.854116 -266.307062)
		(width 0.18288)
		(layer "In6.Cu")
		(net "M_C_CPU0_SA_DQS_DP<4>")
	)
	(segment
		(start 293.090854 -267.928344)
		(end 292.918134 -267.894054)
		(width 0.18288)
		(layer "In6.Cu")
		(net "M_C_CPU0_SA_DQS_DP<4>")
	)
	(segment
		(start 307.67528 -266.095226)
		(end 306.700936 -265.691366)
		(width 0.18288)
		(layer "In6.Cu")
		(net "M_C_CPU0_SA_DQS_DP<4>")
	)
	(segment
		(start 290.979606 -269.371572)
		(end 290.979606 -269.547594)
		(width 0.18288)
		(layer "In6.Cu")
		(net "M_C_CPU0_SA_DQS_DP<4>")
	)
	(segment
		(start 312.166762 -265.206226)
		(end 311.237376 -265.206226)
		(width 0.18288)
		(layer "In6.Cu")
		(net "M_C_CPU0_SA_DQS_DP<4>")
	)
	(segment
		(start 338.276946 -260.11505)
		(end 338.262214 -260.106414)
		(width 0.088646)
		(layer "In6.Cu")
		(net "M_C_CPU0_SA_DQS_DP<4>")
	)
	(segment
		(start 294.037512 -267.146024)
		(end 293.581582 -267.450824)
		(width 0.18288)
		(layer "In6.Cu")
		(net "M_C_CPU0_SA_DQS_DP<4>")
	)
	(segment
		(start 285.891224 -272.783554)
		(end 285.03372 -273.138646)
		(width 0.18288)
		(layer "In6.Cu")
		(net "M_C_CPU0_SA_DQS_DP<4>")
	)
	(segment
		(start 312.649616 -265.00709)
		(end 312.166762 -265.206226)
		(width 0.18288)
		(layer "In6.Cu")
		(net "M_C_CPU0_SA_DQS_DP<4>")
	)
	(segment
		(start 330.681076 -261.022338)
		(end 330.621386 -261.082028)
		(width 0.088646)
		(layer "In6.Cu")
		(net "M_C_CPU0_SA_DQS_DP<4>")
	)
	(segment
		(start 284.437328 -273.138646)
		(end 284.183582 -273.392392)
		(width 0.18288)
		(layer "In6.Cu")
		(net "M_C_CPU0_SA_DQS_DP<4>")
	)
	(segment
		(start 326.152256 -262.375396)
		(end 319.269618 -262.375396)
		(width 0.18288)
		(layer "In6.Cu")
		(net "M_C_CPU0_SA_DQS_DP<4>")
	)
	(segment
		(start 283.689806 -273.392392)
		(end 283.4005 -273.103086)
		(width 0.18288)
		(layer "In6.Cu")
		(net "M_C_CPU0_SA_DQS_DP<4>")
	)
	(segment
		(start 287.16605 -271.508982)
		(end 285.891224 -272.783554)
		(width 0.18288)
		(layer "In6.Cu")
		(net "M_C_CPU0_SA_DQS_DP<4>")
	)
	(segment
		(start 290.027614 -270.323564)
		(end 288.409888 -270.993616)
		(width 0.18288)
		(layer "In6.Cu")
		(net "M_C_CPU0_SA_DQS_DP<4>")
	)
	(segment
		(start 298.81576 -266.59205)
		(end 298.530772 -266.307062)
		(width 0.18288)
		(layer "In6.Cu")
		(net "M_C_CPU0_SA_DQS_DP<4>")
	)
	(segment
		(start 340.151974 -260.11251)
		(end 340.14156 -260.106414)
		(width 0.088646)
		(layer "In6.Cu")
		(net "M_C_CPU0_SA_DQS_DP<4>")
	)
	(segment
		(start 280.911808 -275.244306)
		(end 280.089102 -275.244306)
		(width 0.18288)
		(layer "In6.Cu")
		(net "M_C_CPU0_SA_DQS_DP<4>")
	)
	(segment
		(start 290.979606 -269.547594)
		(end 290.591494 -269.935706)
		(width 0.18288)
		(layer "In6.Cu")
		(net "M_C_CPU0_SA_DQS_DP<4>")
	)
	(segment
		(start 319.269618 -262.375396)
		(end 319.145158 -262.499856)
		(width 0.18288)
		(layer "In6.Cu")
		(net "M_C_CPU0_SA_DQS_DP<4>")
	)
	(segment
		(start 290.415472 -269.935706)
		(end 290.027614 -270.323564)
		(width 0.18288)
		(layer "In6.Cu")
		(net "M_C_CPU0_SA_DQS_DP<4>")
	)
	(segment
		(start 316.841632 -262.95731)
		(end 316.679072 -262.889746)
		(width 0.18288)
		(layer "In6.Cu")
		(net "M_C_CPU0_SA_DQS_DP<4>")
	)
	(segment
		(start 314.860432 -263.77646)
		(end 314.35294 -263.98601)
		(width 0.18288)
		(layer "In6.Cu")
		(net "M_C_CPU0_SA_DQS_DP<4>")
	)
	(segment
		(start 316.679072 -262.889746)
		(end 316.172088 -263.099296)
		(width 0.18288)
		(layer "In6.Cu")
		(net "M_C_CPU0_SA_DQS_DP<4>")
	)
	(segment
		(start 310.378856 -264.850626)
		(end 309.863998 -264.850626)
		(width 0.18288)
		(layer "In6.Cu")
		(net "M_C_CPU0_SA_DQS_DP<4>")
	)
	(segment
		(start 316.172088 -263.099296)
		(end 316.104778 -263.26211)
		(width 0.18288)
		(layer "In6.Cu")
		(net "M_C_CPU0_SA_DQS_DP<4>")
	)
	(segment
		(start 309.180484 -265.133836)
		(end 308.219094 -266.095226)
		(width 0.18288)
		(layer "In6.Cu")
		(net "M_C_CPU0_SA_DQS_DP<4>")
	)
	(segment
		(start 293.581582 -267.450824)
		(end 293.547038 -267.62329)
		(width 0.18288)
		(layer "In6.Cu")
		(net "M_C_CPU0_SA_DQS_DP<4>")
	)
	(segment
		(start 287.67278 -271.299178)
		(end 287.16605 -271.508982)
		(width 0.18288)
		(layer "In6.Cu")
		(net "M_C_CPU0_SA_DQS_DP<4>")
	)
	(segment
		(start 311.237376 -265.206226)
		(end 310.378856 -264.850626)
		(width 0.18288)
		(layer "In6.Cu")
		(net "M_C_CPU0_SA_DQS_DP<4>")
	)
	(segment
		(start 342.274652 -260.251956)
		(end 342.021414 -260.10616)
		(width 0.088646)
		(layer "In6.Cu")
		(net "M_C_CPU0_SA_DQS_DP<4>")
	)
	(segment
		(start 319.145158 -262.499856)
		(end 318.596518 -262.499856)
		(width 0.18288)
		(layer "In6.Cu")
		(net "M_C_CPU0_SA_DQS_DP<4>")
	)
	(segment
		(start 290.591494 -269.935706)
		(end 290.415472 -269.935706)
		(width 0.18288)
		(layer "In6.Cu")
		(net "M_C_CPU0_SA_DQS_DP<4>")
	)
	(segment
		(start 332.170786 -260.165596)
		(end 332.170278 -260.16585)
		(width 0.088646)
		(layer "In6.Cu")
		(net "M_C_CPU0_SA_DQS_DP<4>")
	)
	(segment
		(start 329.275186 -261.082028)
		(end 326.152256 -262.375396)
		(width 0.18288)
		(layer "In6.Cu")
		(net "M_C_CPU0_SA_DQS_DP<4>")
	)
	(segment
		(start 285.03372 -273.138646)
		(end 284.437328 -273.138646)
		(width 0.18288)
		(layer "In6.Cu")
		(net "M_C_CPU0_SA_DQS_DP<4>")
	)
	(segment
		(start 283.4005 -273.103086)
		(end 283.053028 -273.103086)
		(width 0.18288)
		(layer "In6.Cu")
		(net "M_C_CPU0_SA_DQS_DP<4>")
	)
	(segment
		(start 318.596518 -262.499856)
		(end 318.472058 -262.375396)
		(width 0.18288)
		(layer "In6.Cu")
		(net "M_C_CPU0_SA_DQS_DP<4>")
	)
	(segment
		(start 341.646764 -260.106414)
		(end 341.647018 -260.106414)
		(width 0.088646)
		(layer "In6.Cu")
		(net "M_C_CPU0_SA_DQS_DP<4>")
	)
	(segment
		(start 297.00601 -267.155168)
		(end 295.458896 -267.155168)
		(width 0.18288)
		(layer "In6.Cu")
		(net "M_C_CPU0_SA_DQS_DP<4>")
	)
	(segment
		(start 341.096346 -260.11505)
		(end 341.081614 -260.106414)
		(width 0.088646)
		(layer "In6.Cu")
		(net "M_C_CPU0_SA_DQS_DP<4>")
	)
	(segment
		(start 314.19038 -263.918446)
		(end 313.419236 -264.237216)
		(width 0.18288)
		(layer "In6.Cu")
		(net "M_C_CPU0_SA_DQS_DP<4>")
	)
	(segment
		(start 305.266344 -265.815826)
		(end 305.141884 -265.691366)
		(width 0.18288)
		(layer "In6.Cu")
		(net "M_C_CPU0_SA_DQS_DP<4>")
	)
	(segment
		(start 332.012544 -260.32206)
		(end 331.83957 -260.32206)
		(width 0.088646)
		(layer "In6.Cu")
		(net "M_C_CPU0_SA_DQS_DP<4>")
	)
	(segment
		(start 313.419236 -264.237216)
		(end 312.649616 -265.00709)
		(width 0.18288)
		(layer "In6.Cu")
		(net "M_C_CPU0_SA_DQS_DP<4>")
	)
	(segment
		(start 309.863998 -264.850626)
		(end 309.180484 -265.133836)
		(width 0.18288)
		(layer "In6.Cu")
		(net "M_C_CPU0_SA_DQS_DP<4>")
	)
	(segment
		(start 331.139292 -261.022338)
		(end 330.681076 -261.022338)
		(width 0.088646)
		(layer "In6.Cu")
		(net "M_C_CPU0_SA_DQS_DP<4>")
	)
	(segment
		(start 299.54728 -266.316714)
		(end 299.271944 -266.59205)
		(width 0.18288)
		(layer "In6.Cu")
		(net "M_C_CPU0_SA_DQS_DP<4>")
	)
	(segment
		(start 339.767164 -260.106414)
		(end 339.75675 -260.11251)
		(width 0.088646)
		(layer "In6.Cu")
		(net "M_C_CPU0_SA_DQS_DP<4>")
	)
	(segment
		(start 302.732186 -266.316714)
		(end 302.183546 -266.316714)
		(width 0.18288)
		(layer "In6.Cu")
		(net "M_C_CPU0_SA_DQS_DP<4>")
	)
	(segment
		(start 299.271944 -266.59205)
		(end 298.81576 -266.59205)
		(width 0.18288)
		(layer "In6.Cu")
		(net "M_C_CPU0_SA_DQS_DP<4>")
	)
	(segment
		(start 302.059086 -266.441174)
		(end 301.510446 -266.441174)
		(width 0.18288)
		(layer "In6.Cu")
		(net "M_C_CPU0_SA_DQS_DP<4>")
	)
	(segment
		(start 315.597286 -263.47166)
		(end 315.434726 -263.404096)
		(width 0.18288)
		(layer "In6.Cu")
		(net "M_C_CPU0_SA_DQS_DP<4>")
	)
	(segment
		(start 331.83957 -260.32206)
		(end 331.139292 -261.022338)
		(width 0.088646)
		(layer "In6.Cu")
		(net "M_C_CPU0_SA_DQS_DP<4>")
	)
	(segment
		(start 294.715692 -267.442188)
		(end 294.430704 -267.1572)
		(width 0.18288)
		(layer "In6.Cu")
		(net "M_C_CPU0_SA_DQS_DP<4>")
	)
	(segment
		(start 302.183546 -266.316714)
		(end 302.059086 -266.441174)
		(width 0.18288)
		(layer "In6.Cu")
		(net "M_C_CPU0_SA_DQS_DP<4>")
	)
	(segment
		(start 315.434726 -263.404096)
		(end 314.927742 -263.613646)
		(width 0.18288)
		(layer "In6.Cu")
		(net "M_C_CPU0_SA_DQS_DP<4>")
	)
	(segment
		(start 314.927742 -263.613646)
		(end 314.860432 -263.77646)
		(width 0.18288)
		(layer "In6.Cu")
		(net "M_C_CPU0_SA_DQS_DP<4>")
	)
	(segment
		(start 330.598018 -261.082028)
		(end 329.275186 -261.082028)
		(width 0.18288)
		(layer "In6.Cu")
		(net "M_C_CPU0_SA_DQS_DP<4>")
	)
	(segment
		(start 295.458896 -267.155168)
		(end 295.171876 -267.442188)
		(width 0.18288)
		(layer "In6.Cu")
		(net "M_C_CPU0_SA_DQS_DP<4>")
	)
	(segment
		(start 332.170278 -260.16585)
		(end 332.012544 -260.32206)
		(width 0.088646)
		(layer "In6.Cu")
		(net "M_C_CPU0_SA_DQS_DP<4>")
	)
	(segment
		(start 336.392774 -260.11251)
		(end 336.38236 -260.106414)
		(width 0.088646)
		(layer "In6.Cu")
		(net "M_C_CPU0_SA_DQS_DP<4>")
	)
	(arc
		(start 342.702896 -260.29285)
		(mid 342.628211 -260.262345)
		(end 342.54821 -260.251956)
		(width 0.088646)
		(layer "In6.Cu")
		(net "M_C_CPU0_SA_DQS_DP<4>")
	)
	(arc
		(start 341.647018 -260.106414)
		(mid 341.372819 -260.182249)
		(end 341.096346 -260.11505)
		(width 0.088646)
		(layer "In6.Cu")
		(net "M_C_CPU0_SA_DQS_DP<4>")
	)
	(arc
		(start 335.068164 -260.106414)
		(mid 334.785462 -260.18219)
		(end 334.50276 -260.106414)
		(width 0.088646)
		(layer "In6.Cu")
		(net "M_C_CPU0_SA_DQS_DP<4>")
	)
	(arc
		(start 340.707218 -260.106414)
		(mid 340.430405 -260.182284)
		(end 340.151974 -260.11251)
		(width 0.088646)
		(layer "In6.Cu")
		(net "M_C_CPU0_SA_DQS_DP<4>")
	)
	(arc
		(start 340.14156 -260.106414)
		(mid 339.954362 -260.056271)
		(end 339.767164 -260.106414)
		(width 0.088646)
		(layer "In6.Cu")
		(net "M_C_CPU0_SA_DQS_DP<4>")
	)
	(arc
		(start 337.887818 -260.106414)
		(mid 337.613619 -260.182249)
		(end 337.337146 -260.11505)
		(width 0.088646)
		(layer "In6.Cu")
		(net "M_C_CPU0_SA_DQS_DP<4>")
	)
	(arc
		(start 332.248764 -260.106414)
		(mid 332.207834 -260.133447)
		(end 332.170786 -260.165596)
		(width 0.088646)
		(layer "In6.Cu")
		(net "M_C_CPU0_SA_DQS_DP<4>")
	)
	(arc
		(start 337.322414 -260.106414)
		(mid 337.135216 -260.056271)
		(end 336.948018 -260.106414)
		(width 0.088646)
		(layer "In6.Cu")
		(net "M_C_CPU0_SA_DQS_DP<4>")
	)
	(arc
		(start 336.38236 -260.106414)
		(mid 336.195162 -260.056271)
		(end 336.007964 -260.106414)
		(width 0.088646)
		(layer "In6.Cu")
		(net "M_C_CPU0_SA_DQS_DP<4>")
	)
	(arc
		(start 334.128364 -260.106414)
		(mid 333.845662 -260.18219)
		(end 333.56296 -260.106414)
		(width 0.088646)
		(layer "In6.Cu")
		(net "M_C_CPU0_SA_DQS_DP<4>")
	)
	(arc
		(start 336.948018 -260.106414)
		(mid 336.671205 -260.182284)
		(end 336.392774 -260.11251)
		(width 0.088646)
		(layer "In6.Cu")
		(net "M_C_CPU0_SA_DQS_DP<4>")
	)
	(arc
		(start 338.262214 -260.106414)
		(mid 338.075016 -260.056271)
		(end 337.887818 -260.106414)
		(width 0.088646)
		(layer "In6.Cu")
		(net "M_C_CPU0_SA_DQS_DP<4>")
	)
	(arc
		(start 333.188564 -260.106414)
		(mid 332.905862 -260.18219)
		(end 332.62316 -260.106414)
		(width 0.088646)
		(layer "In6.Cu")
		(net "M_C_CPU0_SA_DQS_DP<4>")
	)
	(arc
		(start 338.827618 -260.106414)
		(mid 338.553419 -260.182249)
		(end 338.276946 -260.11505)
		(width 0.088646)
		(layer "In6.Cu")
		(net "M_C_CPU0_SA_DQS_DP<4>")
	)
	(arc
		(start 334.50276 -260.106414)
		(mid 334.315562 -260.056271)
		(end 334.128364 -260.106414)
		(width 0.088646)
		(layer "In6.Cu")
		(net "M_C_CPU0_SA_DQS_DP<4>")
	)
	(arc
		(start 335.44256 -260.106414)
		(mid 335.255362 -260.056271)
		(end 335.068164 -260.106414)
		(width 0.088646)
		(layer "In6.Cu")
		(net "M_C_CPU0_SA_DQS_DP<4>")
	)
	(arc
		(start 333.56296 -260.106414)
		(mid 333.375762 -260.056271)
		(end 333.188564 -260.106414)
		(width 0.088646)
		(layer "In6.Cu")
		(net "M_C_CPU0_SA_DQS_DP<4>")
	)
	(arc
		(start 336.007964 -260.106414)
		(mid 335.725262 -260.18219)
		(end 335.44256 -260.106414)
		(width 0.088646)
		(layer "In6.Cu")
		(net "M_C_CPU0_SA_DQS_DP<4>")
	)
	(arc
		(start 339.202014 -260.106414)
		(mid 339.014816 -260.056271)
		(end 338.827618 -260.106414)
		(width 0.088646)
		(layer "In6.Cu")
		(net "M_C_CPU0_SA_DQS_DP<4>")
	)
	(arc
		(start 339.75675 -260.11251)
		(mid 339.478572 -260.182233)
		(end 339.202014 -260.106414)
		(width 0.088646)
		(layer "In6.Cu")
		(net "M_C_CPU0_SA_DQS_DP<4>")
	)
	(arc
		(start 341.081614 -260.106414)
		(mid 340.894416 -260.056271)
		(end 340.707218 -260.106414)
		(width 0.088646)
		(layer "In6.Cu")
		(net "M_C_CPU0_SA_DQS_DP<4>")
	)
	(arc
		(start 342.02116 -260.106414)
		(mid 341.833962 -260.056271)
		(end 341.646764 -260.106414)
		(width 0.088646)
		(layer "In6.Cu")
		(net "M_C_CPU0_SA_DQS_DP<4>")
	)
	(arc
		(start 332.62316 -260.106414)
		(mid 332.435962 -260.056271)
		(end 332.248764 -260.106414)
		(width 0.088646)
		(layer "In6.Cu")
		(net "M_C_CPU0_SA_DQS_DP<4>")
	)
	(segment
		(start 272.39214 -284.605476)
		(end 271.967198 -284.605476)
		(width 0.20066)
		(layer "F.Cu")
		(net "M_C_CPU0_SA_DQS_DP<3>")
	)
	(segment
		(start 274.143978 -285.301182)
		(end 273.925792 -285.301182)
		(width 0.20066)
		(layer "F.Cu")
		(net "M_C_CPU0_SA_DQS_DP<3>")
	)
	(segment
		(start 276.145752 -285.291784)
		(end 274.390358 -285.291784)
		(width 0.1016)
		(layer "F.Cu")
		(net "M_C_CPU0_SA_DQS_DP<3>")
	)
	(segment
		(start 276.62124 -285.291784)
		(end 276.469094 -285.291784)
		(width 0.20066)
		(layer "F.Cu")
		(net "M_C_CPU0_SA_DQS_DP<3>")
	)
	(segment
		(start 278.711914 -284.866588)
		(end 278.163274 -284.866588)
		(width 0.20066)
		(layer "F.Cu")
		(net "M_C_CPU0_SA_DQS_DP<3>")
	)
	(segment
		(start 277.902162 -284.605476)
		(end 277.63343 -284.605476)
		(width 0.20066)
		(layer "F.Cu")
		(net "M_C_CPU0_SA_DQS_DP<3>")
	)
	(segment
		(start 277.208234 -285.030672)
		(end 276.882352 -285.030672)
		(width 0.20066)
		(layer "F.Cu")
		(net "M_C_CPU0_SA_DQS_DP<3>")
	)
	(segment
		(start 274.390358 -285.291784)
		(end 274.153376 -285.291784)
		(width 0.101854)
		(layer "F.Cu")
		(net "M_C_CPU0_SA_DQS_DP<3>")
	)
	(segment
		(start 343.713562 -264.778236)
		(end 343.713816 -265.314176)
		(width 0.20066)
		(layer "F.Cu")
		(net "M_C_CPU0_SA_DQS_DP<3>")
	)
	(segment
		(start 273.655282 -285.030672)
		(end 273.028156 -285.030672)
		(width 0.20066)
		(layer "F.Cu")
		(net "M_C_CPU0_SA_DQS_DP<3>")
	)
	(segment
		(start 279.816814 -284.866588)
		(end 278.711914 -284.866588)
		(width 0.20066)
		(layer "F.Cu")
		(net "M_C_CPU0_SA_DQS_DP<3>")
	)
	(segment
		(start 271.967198 -284.605476)
		(end 271.706086 -284.866588)
		(width 0.20066)
		(layer "F.Cu")
		(net "M_C_CPU0_SA_DQS_DP<3>")
	)
	(segment
		(start 276.882352 -285.030672)
		(end 276.62124 -285.291784)
		(width 0.20066)
		(layer "F.Cu")
		(net "M_C_CPU0_SA_DQS_DP<3>")
	)
	(segment
		(start 277.63343 -284.605476)
		(end 277.208234 -285.030672)
		(width 0.20066)
		(layer "F.Cu")
		(net "M_C_CPU0_SA_DQS_DP<3>")
	)
	(segment
		(start 278.163274 -284.866588)
		(end 277.902162 -284.605476)
		(width 0.20066)
		(layer "F.Cu")
		(net "M_C_CPU0_SA_DQS_DP<3>")
	)
	(segment
		(start 271.706086 -284.866588)
		(end 271.168114 -284.866588)
		(width 0.20066)
		(layer "F.Cu")
		(net "M_C_CPU0_SA_DQS_DP<3>")
	)
	(segment
		(start 276.469094 -285.291784)
		(end 276.145752 -285.291784)
		(width 0.101854)
		(layer "F.Cu")
		(net "M_C_CPU0_SA_DQS_DP<3>")
	)
	(segment
		(start 274.153376 -285.291784)
		(end 274.143978 -285.301182)
		(width 0.101854)
		(layer "F.Cu")
		(net "M_C_CPU0_SA_DQS_DP<3>")
	)
	(segment
		(start 273.925792 -285.301182)
		(end 273.655282 -285.030672)
		(width 0.20066)
		(layer "F.Cu")
		(net "M_C_CPU0_SA_DQS_DP<3>")
	)
	(segment
		(start 273.028156 -285.030672)
		(end 272.39214 -284.605476)
		(width 0.20066)
		(layer "F.Cu")
		(net "M_C_CPU0_SA_DQS_DP<3>")
	)
	(segment
		(start 298.212002 -280.763218)
		(end 297.51782 -281.051)
		(width 0.18288)
		(layer "In6.Cu")
		(net "M_C_CPU0_SA_DQS_DP<3>")
	)
	(segment
		(start 315.868812 -275.92401)
		(end 313.306714 -276.986492)
		(width 0.18288)
		(layer "In6.Cu")
		(net "M_C_CPU0_SA_DQS_DP<3>")
	)
	(segment
		(start 333.31023 -266.133326)
		(end 332.984602 -266.133326)
		(width 0.088646)
		(layer "In6.Cu")
		(net "M_C_CPU0_SA_DQS_DP<3>")
	)
	(segment
		(start 331.00264 -267.960856)
		(end 330.979272 -267.960856)
		(width 0.088646)
		(layer "In6.Cu")
		(net "M_C_CPU0_SA_DQS_DP<3>")
	)
	(segment
		(start 332.180692 -267.44295)
		(end 331.72273 -267.900912)
		(width 0.088646)
		(layer "In6.Cu")
		(net "M_C_CPU0_SA_DQS_DP<3>")
	)
	(segment
		(start 296.58691 -281.612086)
		(end 295.464484 -281.612086)
		(width 0.18288)
		(layer "In6.Cu")
		(net "M_C_CPU0_SA_DQS_DP<3>")
	)
	(segment
		(start 332.984602 -266.133326)
		(end 332.180692 -266.937236)
		(width 0.088646)
		(layer "In6.Cu")
		(net "M_C_CPU0_SA_DQS_DP<3>")
	)
	(segment
		(start 342.68664 -265.680698)
		(end 342.681814 -265.683238)
		(width 0.088646)
		(layer "In6.Cu")
		(net "M_C_CPU0_SA_DQS_DP<3>")
	)
	(segment
		(start 298.806616 -281.041856)
		(end 298.527978 -280.763218)
		(width 0.18288)
		(layer "In6.Cu")
		(net "M_C_CPU0_SA_DQS_DP<3>")
	)
	(segment
		(start 294.706548 -281.891994)
		(end 294.415464 -281.60091)
		(width 0.18288)
		(layer "In6.Cu")
		(net "M_C_CPU0_SA_DQS_DP<3>")
	)
	(segment
		(start 282.262072 -284.595824)
		(end 281.749246 -284.383226)
		(width 0.18288)
		(layer "In6.Cu")
		(net "M_C_CPU0_SA_DQS_DP<3>")
	)
	(segment
		(start 303.127664 -280.278332)
		(end 302.644048 -280.761948)
		(width 0.18288)
		(layer "In6.Cu")
		(net "M_C_CPU0_SA_DQS_DP<3>")
	)
	(segment
		(start 295.184576 -281.891994)
		(end 294.706548 -281.891994)
		(width 0.18288)
		(layer "In6.Cu")
		(net "M_C_CPU0_SA_DQS_DP<3>")
	)
	(segment
		(start 332.180692 -266.937236)
		(end 332.180692 -267.44295)
		(width 0.088646)
		(layer "In6.Cu")
		(net "M_C_CPU0_SA_DQS_DP<3>")
	)
	(segment
		(start 340.61146 -265.803888)
		(end 340.61146 -265.803634)
		(width 0.088646)
		(layer "In6.Cu")
		(net "M_C_CPU0_SA_DQS_DP<3>")
	)
	(segment
		(start 284.471872 -285.01721)
		(end 284.197298 -285.291784)
		(width 0.18288)
		(layer "In6.Cu")
		(net "M_C_CPU0_SA_DQS_DP<3>")
	)
	(segment
		(start 303.797716 -278.65959)
		(end 303.127664 -280.278332)
		(width 0.18288)
		(layer "In6.Cu")
		(net "M_C_CPU0_SA_DQS_DP<3>")
	)
	(segment
		(start 336.477864 -265.803634)
		(end 336.477864 -265.803888)
		(width 0.088646)
		(layer "In6.Cu")
		(net "M_C_CPU0_SA_DQS_DP<3>")
	)
	(segment
		(start 283.718762 -285.291784)
		(end 283.426916 -284.999938)
		(width 0.18288)
		(layer "In6.Cu")
		(net "M_C_CPU0_SA_DQS_DP<3>")
	)
	(segment
		(start 312.335926 -277.957026)
		(end 311.647586 -277.957026)
		(width 0.18288)
		(layer "In6.Cu")
		(net "M_C_CPU0_SA_DQS_DP<3>")
	)
	(segment
		(start 299.284644 -281.041856)
		(end 298.806616 -281.041856)
		(width 0.18288)
		(layer "In6.Cu")
		(net "M_C_CPU0_SA_DQS_DP<3>")
	)
	(segment
		(start 306.217574 -278.173688)
		(end 304.283618 -278.173688)
		(width 0.18288)
		(layer "In6.Cu")
		(net "M_C_CPU0_SA_DQS_DP<3>")
	)
	(segment
		(start 294.140382 -281.60091)
		(end 293.778686 -281.751024)
		(width 0.18288)
		(layer "In6.Cu")
		(net "M_C_CPU0_SA_DQS_DP<3>")
	)
	(segment
		(start 302.644048 -280.761948)
		(end 299.564552 -280.761948)
		(width 0.18288)
		(layer "In6.Cu")
		(net "M_C_CPU0_SA_DQS_DP<3>")
	)
	(segment
		(start 289.716464 -284.182312)
		(end 287.701228 -285.01721)
		(width 0.18288)
		(layer "In6.Cu")
		(net "M_C_CPU0_SA_DQS_DP<3>")
	)
	(segment
		(start 294.415464 -281.60091)
		(end 294.140382 -281.60091)
		(width 0.18288)
		(layer "In6.Cu")
		(net "M_C_CPU0_SA_DQS_DP<3>")
	)
	(segment
		(start 341.176864 -265.803888)
		(end 341.162132 -265.812524)
		(width 0.088646)
		(layer "In6.Cu")
		(net "M_C_CPU0_SA_DQS_DP<3>")
	)
	(segment
		(start 280.590244 -284.58541)
		(end 280.097992 -284.58541)
		(width 0.18288)
		(layer "In6.Cu")
		(net "M_C_CPU0_SA_DQS_DP<3>")
	)
	(segment
		(start 311.647586 -277.957026)
		(end 310.47182 -277.470108)
		(width 0.18288)
		(layer "In6.Cu")
		(net "M_C_CPU0_SA_DQS_DP<3>")
	)
	(segment
		(start 313.306714 -276.986492)
		(end 312.335926 -277.957026)
		(width 0.18288)
		(layer "In6.Cu")
		(net "M_C_CPU0_SA_DQS_DP<3>")
	)
	(segment
		(start 330.274422 -267.960856)
		(end 319.274444 -272.518378)
		(width 0.18288)
		(layer "In6.Cu")
		(net "M_C_CPU0_SA_DQS_DP<3>")
	)
	(segment
		(start 342.681814 -265.683238)
		(end 342.326214 -265.683238)
		(width 0.088646)
		(layer "In6.Cu")
		(net "M_C_CPU0_SA_DQS_DP<3>")
	)
	(segment
		(start 280.097992 -284.58541)
		(end 279.816814 -284.866588)
		(width 0.18288)
		(layer "In6.Cu")
		(net "M_C_CPU0_SA_DQS_DP<3>")
	)
	(segment
		(start 295.464484 -281.612086)
		(end 295.184576 -281.891994)
		(width 0.18288)
		(layer "In6.Cu")
		(net "M_C_CPU0_SA_DQS_DP<3>")
	)
	(segment
		(start 341.551514 -265.803634)
		(end 341.55126 -265.803888)
		(width 0.088646)
		(layer "In6.Cu")
		(net "M_C_CPU0_SA_DQS_DP<3>")
	)
	(segment
		(start 307.915564 -277.470108)
		(end 306.217574 -278.173688)
		(width 0.18288)
		(layer "In6.Cu")
		(net "M_C_CPU0_SA_DQS_DP<3>")
	)
	(segment
		(start 298.527978 -280.763218)
		(end 298.212002 -280.763218)
		(width 0.18288)
		(layer "In6.Cu")
		(net "M_C_CPU0_SA_DQS_DP<3>")
	)
	(segment
		(start 290.294314 -283.604462)
		(end 289.716464 -284.182312)
		(width 0.18288)
		(layer "In6.Cu")
		(net "M_C_CPU0_SA_DQS_DP<3>")
	)
	(segment
		(start 342.326214 -265.683238)
		(end 342.102694 -265.812016)
		(width 0.088646)
		(layer "In6.Cu")
		(net "M_C_CPU0_SA_DQS_DP<3>")
	)
	(segment
		(start 287.701228 -285.01721)
		(end 284.471872 -285.01721)
		(width 0.18288)
		(layer "In6.Cu")
		(net "M_C_CPU0_SA_DQS_DP<3>")
	)
	(segment
		(start 281.078432 -284.383226)
		(end 280.590244 -284.58541)
		(width 0.18288)
		(layer "In6.Cu")
		(net "M_C_CPU0_SA_DQS_DP<3>")
	)
	(segment
		(start 310.47182 -277.470108)
		(end 307.915564 -277.470108)
		(width 0.18288)
		(layer "In6.Cu")
		(net "M_C_CPU0_SA_DQS_DP<3>")
	)
	(segment
		(start 342.74379 -265.687556)
		(end 342.68664 -265.680698)
		(width 0.088646)
		(layer "In6.Cu")
		(net "M_C_CPU0_SA_DQS_DP<3>")
	)
	(segment
		(start 331.062584 -267.900912)
		(end 331.00264 -267.960856)
		(width 0.088646)
		(layer "In6.Cu")
		(net "M_C_CPU0_SA_DQS_DP<3>")
	)
	(segment
		(start 333.580486 -265.86307)
		(end 333.31023 -266.133326)
		(width 0.088646)
		(layer "In6.Cu")
		(net "M_C_CPU0_SA_DQS_DP<3>")
	)
	(segment
		(start 282.666694 -284.999938)
		(end 282.262072 -284.595824)
		(width 0.18288)
		(layer "In6.Cu")
		(net "M_C_CPU0_SA_DQS_DP<3>")
	)
	(segment
		(start 293.0779 -282.45181)
		(end 290.294314 -283.604462)
		(width 0.18288)
		(layer "In6.Cu")
		(net "M_C_CPU0_SA_DQS_DP<3>")
	)
	(segment
		(start 284.197298 -285.291784)
		(end 283.718762 -285.291784)
		(width 0.18288)
		(layer "In6.Cu")
		(net "M_C_CPU0_SA_DQS_DP<3>")
	)
	(segment
		(start 304.283618 -278.173688)
		(end 303.797716 -278.65959)
		(width 0.18288)
		(layer "In6.Cu")
		(net "M_C_CPU0_SA_DQS_DP<3>")
	)
	(segment
		(start 297.51782 -281.051)
		(end 297.217846 -281.350974)
		(width 0.18288)
		(layer "In6.Cu")
		(net "M_C_CPU0_SA_DQS_DP<3>")
	)
	(segment
		(start 331.72273 -267.900912)
		(end 331.062584 -267.900912)
		(width 0.088646)
		(layer "In6.Cu")
		(net "M_C_CPU0_SA_DQS_DP<3>")
	)
	(segment
		(start 319.274444 -272.518378)
		(end 315.868812 -275.92401)
		(width 0.18288)
		(layer "In6.Cu")
		(net "M_C_CPU0_SA_DQS_DP<3>")
	)
	(segment
		(start 283.426916 -284.999938)
		(end 282.666694 -284.999938)
		(width 0.18288)
		(layer "In6.Cu")
		(net "M_C_CPU0_SA_DQS_DP<3>")
	)
	(segment
		(start 299.564552 -280.761948)
		(end 299.284644 -281.041856)
		(width 0.18288)
		(layer "In6.Cu")
		(net "M_C_CPU0_SA_DQS_DP<3>")
	)
	(segment
		(start 297.217846 -281.350974)
		(end 296.58691 -281.612086)
		(width 0.18288)
		(layer "In6.Cu")
		(net "M_C_CPU0_SA_DQS_DP<3>")
	)
	(segment
		(start 330.979272 -267.960856)
		(end 330.274422 -267.960856)
		(width 0.18288)
		(layer "In6.Cu")
		(net "M_C_CPU0_SA_DQS_DP<3>")
	)
	(segment
		(start 293.778686 -281.751024)
		(end 293.0779 -282.45181)
		(width 0.18288)
		(layer "In6.Cu")
		(net "M_C_CPU0_SA_DQS_DP<3>")
	)
	(segment
		(start 339.297264 -265.803634)
		(end 339.282532 -265.81227)
		(width 0.088646)
		(layer "In6.Cu")
		(net "M_C_CPU0_SA_DQS_DP<3>")
	)
	(segment
		(start 281.749246 -284.383226)
		(end 281.078432 -284.383226)
		(width 0.18288)
		(layer "In6.Cu")
		(net "M_C_CPU0_SA_DQS_DP<3>")
	)
	(segment
		(start 343.373456 -265.404092)
		(end 342.94826 -265.6459)
		(width 0.088646)
		(layer "In6.Cu")
		(net "M_C_CPU0_SA_DQS_DP<3>")
	)
	(arc
		(start 336.85226 -265.803634)
		(mid 336.665062 -265.753491)
		(end 336.477864 -265.803634)
		(width 0.088646)
		(layer "In6.Cu")
		(net "M_C_CPU0_SA_DQS_DP<3>")
	)
	(arc
		(start 333.658464 -265.803888)
		(mid 333.617534 -265.830921)
		(end 333.580486 -265.86307)
		(width 0.088646)
		(layer "In6.Cu")
		(net "M_C_CPU0_SA_DQS_DP<3>")
	)
	(arc
		(start 340.237064 -265.803634)
		(mid 339.954362 -265.87941)
		(end 339.67166 -265.803634)
		(width 0.088646)
		(layer "In6.Cu")
		(net "M_C_CPU0_SA_DQS_DP<3>")
	)
	(arc
		(start 335.91246 -265.803888)
		(mid 335.725262 -265.753745)
		(end 335.538064 -265.803888)
		(width 0.088646)
		(layer "In6.Cu")
		(net "M_C_CPU0_SA_DQS_DP<3>")
	)
	(arc
		(start 340.61146 -265.803634)
		(mid 340.424262 -265.753491)
		(end 340.237064 -265.803634)
		(width 0.088646)
		(layer "In6.Cu")
		(net "M_C_CPU0_SA_DQS_DP<3>")
	)
	(arc
		(start 336.477864 -265.803888)
		(mid 336.195162 -265.87963)
		(end 335.91246 -265.803888)
		(width 0.088646)
		(layer "In6.Cu")
		(net "M_C_CPU0_SA_DQS_DP<3>")
	)
	(arc
		(start 338.73186 -265.803634)
		(mid 338.544662 -265.753491)
		(end 338.357464 -265.803634)
		(width 0.088646)
		(layer "In6.Cu")
		(net "M_C_CPU0_SA_DQS_DP<3>")
	)
	(arc
		(start 334.97266 -265.803888)
		(mid 334.785462 -265.753745)
		(end 334.598264 -265.803888)
		(width 0.088646)
		(layer "In6.Cu")
		(net "M_C_CPU0_SA_DQS_DP<3>")
	)
	(arc
		(start 343.713816 -265.314176)
		(mid 343.537795 -265.337013)
		(end 343.373456 -265.404092)
		(width 0.088646)
		(layer "In6.Cu")
		(net "M_C_CPU0_SA_DQS_DP<3>")
	)
	(arc
		(start 342.102694 -265.812016)
		(mid 341.826029 -265.879487)
		(end 341.551514 -265.803634)
		(width 0.088646)
		(layer "In6.Cu")
		(net "M_C_CPU0_SA_DQS_DP<3>")
	)
	(arc
		(start 337.417664 -265.803634)
		(mid 337.134962 -265.87941)
		(end 336.85226 -265.803634)
		(width 0.088646)
		(layer "In6.Cu")
		(net "M_C_CPU0_SA_DQS_DP<3>")
	)
	(arc
		(start 334.03286 -265.803888)
		(mid 333.845662 -265.753745)
		(end 333.658464 -265.803888)
		(width 0.088646)
		(layer "In6.Cu")
		(net "M_C_CPU0_SA_DQS_DP<3>")
	)
	(arc
		(start 339.282532 -265.81227)
		(mid 339.006057 -265.87959)
		(end 338.73186 -265.803634)
		(width 0.088646)
		(layer "In6.Cu")
		(net "M_C_CPU0_SA_DQS_DP<3>")
	)
	(arc
		(start 341.162132 -265.812524)
		(mid 340.885691 -265.87969)
		(end 340.61146 -265.803888)
		(width 0.088646)
		(layer "In6.Cu")
		(net "M_C_CPU0_SA_DQS_DP<3>")
	)
	(arc
		(start 339.67166 -265.803634)
		(mid 339.484462 -265.753491)
		(end 339.297264 -265.803634)
		(width 0.088646)
		(layer "In6.Cu")
		(net "M_C_CPU0_SA_DQS_DP<3>")
	)
	(arc
		(start 335.538064 -265.803888)
		(mid 335.255362 -265.87963)
		(end 334.97266 -265.803888)
		(width 0.088646)
		(layer "In6.Cu")
		(net "M_C_CPU0_SA_DQS_DP<3>")
	)
	(arc
		(start 337.79206 -265.803634)
		(mid 337.604862 -265.753491)
		(end 337.417664 -265.803634)
		(width 0.088646)
		(layer "In6.Cu")
		(net "M_C_CPU0_SA_DQS_DP<3>")
	)
	(arc
		(start 342.94826 -265.6459)
		(mid 342.849418 -265.68341)
		(end 342.74379 -265.687556)
		(width 0.088646)
		(layer "In6.Cu")
		(net "M_C_CPU0_SA_DQS_DP<3>")
	)
	(arc
		(start 341.55126 -265.803888)
		(mid 341.364062 -265.753745)
		(end 341.176864 -265.803888)
		(width 0.088646)
		(layer "In6.Cu")
		(net "M_C_CPU0_SA_DQS_DP<3>")
	)
	(arc
		(start 338.357464 -265.803634)
		(mid 338.074762 -265.87941)
		(end 337.79206 -265.803634)
		(width 0.088646)
		(layer "In6.Cu")
		(net "M_C_CPU0_SA_DQS_DP<3>")
	)
	(arc
		(start 334.598264 -265.803888)
		(mid 334.315562 -265.87963)
		(end 334.03286 -265.803888)
		(width 0.088646)
		(layer "In6.Cu")
		(net "M_C_CPU0_SA_DQS_DP<3>")
	)
	(segment
		(start 273.028156 -294.380666)
		(end 272.39214 -293.95547)
		(width 0.20066)
		(layer "F.Cu")
		(net "M_C_CPU0_SA_DQS_DP<2>")
	)
	(segment
		(start 272.39214 -293.95547)
		(end 271.967198 -293.95547)
		(width 0.20066)
		(layer "F.Cu")
		(net "M_C_CPU0_SA_DQS_DP<2>")
	)
	(segment
		(start 271.706086 -294.216582)
		(end 271.168114 -294.216582)
		(width 0.20066)
		(layer "F.Cu")
		(net "M_C_CPU0_SA_DQS_DP<2>")
	)
	(segment
		(start 340.424516 -267.219938)
		(end 340.424262 -267.755878)
		(width 0.20066)
		(layer "F.Cu")
		(net "M_C_CPU0_SA_DQS_DP<2>")
	)
	(segment
		(start 278.711914 -294.216582)
		(end 278.163274 -294.216582)
		(width 0.20066)
		(layer "F.Cu")
		(net "M_C_CPU0_SA_DQS_DP<2>")
	)
	(segment
		(start 273.655282 -294.380666)
		(end 273.028156 -294.380666)
		(width 0.20066)
		(layer "F.Cu")
		(net "M_C_CPU0_SA_DQS_DP<2>")
	)
	(segment
		(start 276.145752 -294.641778)
		(end 274.390358 -294.641778)
		(width 0.1016)
		(layer "F.Cu")
		(net "M_C_CPU0_SA_DQS_DP<2>")
	)
	(segment
		(start 276.882352 -294.380666)
		(end 276.62124 -294.641778)
		(width 0.20066)
		(layer "F.Cu")
		(net "M_C_CPU0_SA_DQS_DP<2>")
	)
	(segment
		(start 274.390358 -294.641778)
		(end 274.153376 -294.641778)
		(width 0.101854)
		(layer "F.Cu")
		(net "M_C_CPU0_SA_DQS_DP<2>")
	)
	(segment
		(start 276.62124 -294.641778)
		(end 276.469094 -294.641778)
		(width 0.20066)
		(layer "F.Cu")
		(net "M_C_CPU0_SA_DQS_DP<2>")
	)
	(segment
		(start 271.967198 -293.95547)
		(end 271.706086 -294.216582)
		(width 0.20066)
		(layer "F.Cu")
		(net "M_C_CPU0_SA_DQS_DP<2>")
	)
	(segment
		(start 274.143978 -294.651176)
		(end 273.925792 -294.651176)
		(width 0.20066)
		(layer "F.Cu")
		(net "M_C_CPU0_SA_DQS_DP<2>")
	)
	(segment
		(start 276.469094 -294.641778)
		(end 276.145752 -294.641778)
		(width 0.101854)
		(layer "F.Cu")
		(net "M_C_CPU0_SA_DQS_DP<2>")
	)
	(segment
		(start 279.816814 -294.216582)
		(end 278.711914 -294.216582)
		(width 0.20066)
		(layer "F.Cu")
		(net "M_C_CPU0_SA_DQS_DP<2>")
	)
	(segment
		(start 274.153376 -294.641778)
		(end 274.143978 -294.651176)
		(width 0.101854)
		(layer "F.Cu")
		(net "M_C_CPU0_SA_DQS_DP<2>")
	)
	(segment
		(start 278.163274 -294.216582)
		(end 277.902162 -293.95547)
		(width 0.20066)
		(layer "F.Cu")
		(net "M_C_CPU0_SA_DQS_DP<2>")
	)
	(segment
		(start 273.925792 -294.651176)
		(end 273.655282 -294.380666)
		(width 0.20066)
		(layer "F.Cu")
		(net "M_C_CPU0_SA_DQS_DP<2>")
	)
	(segment
		(start 277.208234 -294.380666)
		(end 276.882352 -294.380666)
		(width 0.20066)
		(layer "F.Cu")
		(net "M_C_CPU0_SA_DQS_DP<2>")
	)
	(segment
		(start 277.902162 -293.95547)
		(end 277.63343 -293.95547)
		(width 0.20066)
		(layer "F.Cu")
		(net "M_C_CPU0_SA_DQS_DP<2>")
	)
	(segment
		(start 277.63343 -293.95547)
		(end 277.208234 -294.380666)
		(width 0.20066)
		(layer "F.Cu")
		(net "M_C_CPU0_SA_DQS_DP<2>")
	)
	(segment
		(start 296.126916 -294.953182)
		(end 295.854628 -295.22547)
		(width 0.18288)
		(layer "In4.Cu")
		(net "M_C_CPU0_SA_DQS_DP<2>")
	)
	(segment
		(start 339.454236 -268.129258)
		(end 339.397086 -268.1224)
		(width 0.088646)
		(layer "In4.Cu")
		(net "M_C_CPU0_SA_DQS_DP<2>")
	)
	(segment
		(start 333.188564 -268.245336)
		(end 333.188056 -268.24559)
		(width 0.088646)
		(layer "In4.Cu")
		(net "M_C_CPU0_SA_DQS_DP<2>")
	)
	(segment
		(start 331.341984 -269.563596)
		(end 331.28204 -269.62354)
		(width 0.088646)
		(layer "In4.Cu")
		(net "M_C_CPU0_SA_DQS_DP<2>")
	)
	(segment
		(start 336.382614 -268.245336)
		(end 336.382614 -268.245082)
		(width 0.088646)
		(layer "In4.Cu")
		(net "M_C_CPU0_SA_DQS_DP<2>")
	)
	(segment
		(start 295.355264 -295.22547)
		(end 295.089072 -295.491662)
		(width 0.18288)
		(layer "In4.Cu")
		(net "M_C_CPU0_SA_DQS_DP<2>")
	)
	(segment
		(start 332.48981 -268.712696)
		(end 331.63891 -269.563596)
		(width 0.088646)
		(layer "In4.Cu")
		(net "M_C_CPU0_SA_DQS_DP<2>")
	)
	(segment
		(start 331.258672 -269.62354)
		(end 330.45146 -269.62354)
		(width 0.18288)
		(layer "In4.Cu")
		(net "M_C_CPU0_SA_DQS_DP<2>")
	)
	(segment
		(start 337.891882 -268.242796)
		(end 337.887564 -268.245336)
		(width 0.088646)
		(layer "In4.Cu")
		(net "M_C_CPU0_SA_DQS_DP<2>")
	)
	(segment
		(start 289.069018 -293.696644)
		(end 287.437322 -294.373046)
		(width 0.18288)
		(layer "In4.Cu")
		(net "M_C_CPU0_SA_DQS_DP<2>")
	)
	(segment
		(start 339.39226 -268.12494)
		(end 339.03666 -268.12494)
		(width 0.088646)
		(layer "In4.Cu")
		(net "M_C_CPU0_SA_DQS_DP<2>")
	)
	(segment
		(start 339.397086 -268.1224)
		(end 339.39226 -268.12494)
		(width 0.088646)
		(layer "In4.Cu")
		(net "M_C_CPU0_SA_DQS_DP<2>")
	)
	(segment
		(start 298.17949 -294.370252)
		(end 296.77487 -294.953182)
		(width 0.18288)
		(layer "In4.Cu")
		(net "M_C_CPU0_SA_DQS_DP<2>")
	)
	(segment
		(start 282.131262 -293.68877)
		(end 281.120596 -293.68877)
		(width 0.18288)
		(layer "In4.Cu")
		(net "M_C_CPU0_SA_DQS_DP<2>")
	)
	(segment
		(start 332.853284 -268.56182)
		(end 332.48981 -268.712696)
		(width 0.088646)
		(layer "In4.Cu")
		(net "M_C_CPU0_SA_DQS_DP<2>")
	)
	(segment
		(start 296.77487 -294.953182)
		(end 296.126916 -294.953182)
		(width 0.18288)
		(layer "In4.Cu")
		(net "M_C_CPU0_SA_DQS_DP<2>")
	)
	(segment
		(start 331.63891 -269.563596)
		(end 331.341984 -269.563596)
		(width 0.088646)
		(layer "In4.Cu")
		(net "M_C_CPU0_SA_DQS_DP<2>")
	)
	(segment
		(start 312.01233 -289.315398)
		(end 309.20309 -290.47948)
		(width 0.18288)
		(layer "In4.Cu")
		(net "M_C_CPU0_SA_DQS_DP<2>")
	)
	(segment
		(start 280.086816 -293.94658)
		(end 279.816814 -294.216582)
		(width 0.18288)
		(layer "In4.Cu")
		(net "M_C_CPU0_SA_DQS_DP<2>")
	)
	(segment
		(start 298.541186 -294.370252)
		(end 298.17949 -294.370252)
		(width 0.18288)
		(layer "In4.Cu")
		(net "M_C_CPU0_SA_DQS_DP<2>")
	)
	(segment
		(start 294.437308 -295.216326)
		(end 293.809928 -295.216326)
		(width 0.18288)
		(layer "In4.Cu")
		(net "M_C_CPU0_SA_DQS_DP<2>")
	)
	(segment
		(start 336.382614 -268.245082)
		(end 336.38236 -268.245336)
		(width 0.088646)
		(layer "In4.Cu")
		(net "M_C_CPU0_SA_DQS_DP<2>")
	)
	(segment
		(start 313.239912 -289.07105)
		(end 312.01233 -289.315398)
		(width 0.18288)
		(layer "In4.Cu")
		(net "M_C_CPU0_SA_DQS_DP<2>")
	)
	(segment
		(start 340.083902 -267.845794)
		(end 339.658706 -268.087602)
		(width 0.088646)
		(layer "In4.Cu")
		(net "M_C_CPU0_SA_DQS_DP<2>")
	)
	(segment
		(start 299.476414 -294.386508)
		(end 299.221144 -294.641778)
		(width 0.18288)
		(layer "In4.Cu")
		(net "M_C_CPU0_SA_DQS_DP<2>")
	)
	(segment
		(start 293.809928 -295.216326)
		(end 292.290246 -293.696644)
		(width 0.18288)
		(layer "In4.Cu")
		(net "M_C_CPU0_SA_DQS_DP<2>")
	)
	(segment
		(start 314.271152 -288.707322)
		(end 313.866022 -288.707322)
		(width 0.18288)
		(layer "In4.Cu")
		(net "M_C_CPU0_SA_DQS_DP<2>")
	)
	(segment
		(start 331.28204 -269.62354)
		(end 331.258672 -269.62354)
		(width 0.088646)
		(layer "In4.Cu")
		(net "M_C_CPU0_SA_DQS_DP<2>")
	)
	(segment
		(start 300.285404 -294.386508)
		(end 299.476414 -294.386508)
		(width 0.18288)
		(layer "In4.Cu")
		(net "M_C_CPU0_SA_DQS_DP<2>")
	)
	(segment
		(start 336.951574 -268.24305)
		(end 336.947764 -268.245336)
		(width 0.088646)
		(layer "In4.Cu")
		(net "M_C_CPU0_SA_DQS_DP<2>")
	)
	(segment
		(start 309.20309 -290.47948)
		(end 307.528214 -292.153848)
		(width 0.18288)
		(layer "In4.Cu")
		(net "M_C_CPU0_SA_DQS_DP<2>")
	)
	(segment
		(start 295.089072 -295.491662)
		(end 294.712644 -295.491662)
		(width 0.18288)
		(layer "In4.Cu")
		(net "M_C_CPU0_SA_DQS_DP<2>")
	)
	(segment
		(start 299.221144 -294.641778)
		(end 298.812712 -294.641778)
		(width 0.18288)
		(layer "In4.Cu")
		(net "M_C_CPU0_SA_DQS_DP<2>")
	)
	(segment
		(start 284.19425 -294.641778)
		(end 283.722826 -294.641778)
		(width 0.18288)
		(layer "In4.Cu")
		(net "M_C_CPU0_SA_DQS_DP<2>")
	)
	(segment
		(start 301.396654 -293.275258)
		(end 300.285404 -294.386508)
		(width 0.18288)
		(layer "In4.Cu")
		(net "M_C_CPU0_SA_DQS_DP<2>")
	)
	(segment
		(start 319.608454 -280.466546)
		(end 317.843916 -284.726126)
		(width 0.18288)
		(layer "In4.Cu")
		(net "M_C_CPU0_SA_DQS_DP<2>")
	)
	(segment
		(start 304.82159 -293.275258)
		(end 301.396654 -293.275258)
		(width 0.18288)
		(layer "In4.Cu")
		(net "M_C_CPU0_SA_DQS_DP<2>")
	)
	(segment
		(start 298.812712 -294.641778)
		(end 298.541186 -294.370252)
		(width 0.18288)
		(layer "In4.Cu")
		(net "M_C_CPU0_SA_DQS_DP<2>")
	)
	(segment
		(start 282.82138 -294.378888)
		(end 282.131262 -293.68877)
		(width 0.18288)
		(layer "In4.Cu")
		(net "M_C_CPU0_SA_DQS_DP<2>")
	)
	(segment
		(start 336.94624 -268.246098)
		(end 336.941922 -268.248638)
		(width 0.088646)
		(layer "In4.Cu")
		(net "M_C_CPU0_SA_DQS_DP<2>")
	)
	(segment
		(start 314.535058 -288.034476)
		(end 314.535058 -288.443416)
		(width 0.18288)
		(layer "In4.Cu")
		(net "M_C_CPU0_SA_DQS_DP<2>")
	)
	(segment
		(start 281.120596 -293.68877)
		(end 280.862786 -293.94658)
		(width 0.18288)
		(layer "In4.Cu")
		(net "M_C_CPU0_SA_DQS_DP<2>")
	)
	(segment
		(start 317.843916 -284.726126)
		(end 314.535058 -288.034476)
		(width 0.18288)
		(layer "In4.Cu")
		(net "M_C_CPU0_SA_DQS_DP<2>")
	)
	(segment
		(start 280.862786 -293.94658)
		(end 280.086816 -293.94658)
		(width 0.18288)
		(layer "In4.Cu")
		(net "M_C_CPU0_SA_DQS_DP<2>")
	)
	(segment
		(start 333.110586 -268.304518)
		(end 332.853284 -268.56182)
		(width 0.088646)
		(layer "In4.Cu")
		(net "M_C_CPU0_SA_DQS_DP<2>")
	)
	(segment
		(start 295.854628 -295.22547)
		(end 295.355264 -295.22547)
		(width 0.18288)
		(layer "In4.Cu")
		(net "M_C_CPU0_SA_DQS_DP<2>")
	)
	(segment
		(start 283.722826 -294.641778)
		(end 283.459936 -294.378888)
		(width 0.18288)
		(layer "In4.Cu")
		(net "M_C_CPU0_SA_DQS_DP<2>")
	)
	(segment
		(start 307.528214 -292.153848)
		(end 304.82159 -293.275258)
		(width 0.18288)
		(layer "In4.Cu")
		(net "M_C_CPU0_SA_DQS_DP<2>")
	)
	(segment
		(start 283.459936 -294.378888)
		(end 282.82138 -294.378888)
		(width 0.18288)
		(layer "In4.Cu")
		(net "M_C_CPU0_SA_DQS_DP<2>")
	)
	(segment
		(start 284.462982 -294.373046)
		(end 284.19425 -294.641778)
		(width 0.18288)
		(layer "In4.Cu")
		(net "M_C_CPU0_SA_DQS_DP<2>")
	)
	(segment
		(start 339.03666 -268.12494)
		(end 338.81314 -268.253718)
		(width 0.088646)
		(layer "In4.Cu")
		(net "M_C_CPU0_SA_DQS_DP<2>")
	)
	(segment
		(start 314.535058 -288.443416)
		(end 314.271152 -288.707322)
		(width 0.18288)
		(layer "In4.Cu")
		(net "M_C_CPU0_SA_DQS_DP<2>")
	)
	(segment
		(start 313.866022 -288.707322)
		(end 313.687714 -288.88563)
		(width 0.18288)
		(layer "In4.Cu")
		(net "M_C_CPU0_SA_DQS_DP<2>")
	)
	(segment
		(start 294.712644 -295.491662)
		(end 294.437308 -295.216326)
		(width 0.18288)
		(layer "In4.Cu")
		(net "M_C_CPU0_SA_DQS_DP<2>")
	)
	(segment
		(start 287.437322 -294.373046)
		(end 284.462982 -294.373046)
		(width 0.18288)
		(layer "In4.Cu")
		(net "M_C_CPU0_SA_DQS_DP<2>")
	)
	(segment
		(start 292.290246 -293.696644)
		(end 289.069018 -293.696644)
		(width 0.18288)
		(layer "In4.Cu")
		(net "M_C_CPU0_SA_DQS_DP<2>")
	)
	(segment
		(start 313.687714 -288.88563)
		(end 313.239912 -289.07105)
		(width 0.18288)
		(layer "In4.Cu")
		(net "M_C_CPU0_SA_DQS_DP<2>")
	)
	(segment
		(start 336.947764 -268.245336)
		(end 336.94624 -268.246098)
		(width 0.088646)
		(layer "In4.Cu")
		(net "M_C_CPU0_SA_DQS_DP<2>")
	)
	(segment
		(start 338.26196 -268.245336)
		(end 338.262214 -268.245336)
		(width 0.088646)
		(layer "In4.Cu")
		(net "M_C_CPU0_SA_DQS_DP<2>")
	)
	(segment
		(start 330.45146 -269.62354)
		(end 319.608454 -280.466546)
		(width 0.18288)
		(layer "In4.Cu")
		(net "M_C_CPU0_SA_DQS_DP<2>")
	)
	(arc
		(start 333.56296 -268.245336)
		(mid 333.375762 -268.195193)
		(end 333.188564 -268.245336)
		(width 0.088646)
		(layer "In4.Cu")
		(net "M_C_CPU0_SA_DQS_DP<2>")
	)
	(arc
		(start 335.068164 -268.245336)
		(mid 334.785462 -268.321112)
		(end 334.50276 -268.245336)
		(width 0.088646)
		(layer "In4.Cu")
		(net "M_C_CPU0_SA_DQS_DP<2>")
	)
	(arc
		(start 336.007964 -268.245336)
		(mid 335.725262 -268.321112)
		(end 335.44256 -268.245336)
		(width 0.088646)
		(layer "In4.Cu")
		(net "M_C_CPU0_SA_DQS_DP<2>")
	)
	(arc
		(start 335.44256 -268.245336)
		(mid 335.255362 -268.195193)
		(end 335.068164 -268.245336)
		(width 0.088646)
		(layer "In4.Cu")
		(net "M_C_CPU0_SA_DQS_DP<2>")
	)
	(arc
		(start 340.424262 -267.755878)
		(mid 340.248241 -267.778715)
		(end 340.083902 -267.845794)
		(width 0.088646)
		(layer "In4.Cu")
		(net "M_C_CPU0_SA_DQS_DP<2>")
	)
	(arc
		(start 336.38236 -268.245336)
		(mid 336.195162 -268.195193)
		(end 336.007964 -268.245336)
		(width 0.088646)
		(layer "In4.Cu")
		(net "M_C_CPU0_SA_DQS_DP<2>")
	)
	(arc
		(start 334.128364 -268.245336)
		(mid 333.845662 -268.321112)
		(end 333.56296 -268.245336)
		(width 0.088646)
		(layer "In4.Cu")
		(net "M_C_CPU0_SA_DQS_DP<2>")
	)
	(arc
		(start 333.188056 -268.24559)
		(mid 333.147401 -268.272529)
		(end 333.110586 -268.304518)
		(width 0.088646)
		(layer "In4.Cu")
		(net "M_C_CPU0_SA_DQS_DP<2>")
	)
	(arc
		(start 339.658706 -268.087602)
		(mid 339.559864 -268.125112)
		(end 339.454236 -268.129258)
		(width 0.088646)
		(layer "In4.Cu")
		(net "M_C_CPU0_SA_DQS_DP<2>")
	)
	(arc
		(start 336.941922 -268.248638)
		(mid 336.661817 -268.32108)
		(end 336.382614 -268.245336)
		(width 0.088646)
		(layer "In4.Cu")
		(net "M_C_CPU0_SA_DQS_DP<2>")
	)
	(arc
		(start 337.887564 -268.245336)
		(mid 337.605006 -268.320985)
		(end 337.322414 -268.245336)
		(width 0.088646)
		(layer "In4.Cu")
		(net "M_C_CPU0_SA_DQS_DP<2>")
	)
	(arc
		(start 334.50276 -268.245336)
		(mid 334.315562 -268.195193)
		(end 334.128364 -268.245336)
		(width 0.088646)
		(layer "In4.Cu")
		(net "M_C_CPU0_SA_DQS_DP<2>")
	)
	(arc
		(start 338.262214 -268.245336)
		(mid 338.077377 -268.195075)
		(end 337.891882 -268.242796)
		(width 0.088646)
		(layer "In4.Cu")
		(net "M_C_CPU0_SA_DQS_DP<2>")
	)
	(arc
		(start 338.81314 -268.253718)
		(mid 338.536475 -268.321189)
		(end 338.26196 -268.245336)
		(width 0.088646)
		(layer "In4.Cu")
		(net "M_C_CPU0_SA_DQS_DP<2>")
	)
	(arc
		(start 337.322414 -268.245336)
		(mid 337.137293 -268.195073)
		(end 336.951574 -268.24305)
		(width 0.088646)
		(layer "In4.Cu")
		(net "M_C_CPU0_SA_DQS_DP<2>")
	)
	(segment
		(start 277.63343 -303.305464)
		(end 277.208234 -303.73066)
		(width 0.20066)
		(layer "F.Cu")
		(net "M_C_CPU0_SA_DQS_DP<1>")
	)
	(segment
		(start 273.655282 -303.73066)
		(end 273.028156 -303.73066)
		(width 0.20066)
		(layer "F.Cu")
		(net "M_C_CPU0_SA_DQS_DP<1>")
	)
	(segment
		(start 276.62124 -303.991772)
		(end 276.469094 -303.991772)
		(width 0.20066)
		(layer "F.Cu")
		(net "M_C_CPU0_SA_DQS_DP<1>")
	)
	(segment
		(start 276.469094 -303.991772)
		(end 276.145752 -303.991772)
		(width 0.101854)
		(layer "F.Cu")
		(net "M_C_CPU0_SA_DQS_DP<1>")
	)
	(segment
		(start 273.028156 -303.73066)
		(end 272.39214 -303.305464)
		(width 0.20066)
		(layer "F.Cu")
		(net "M_C_CPU0_SA_DQS_DP<1>")
	)
	(segment
		(start 274.143978 -304.00117)
		(end 273.925792 -304.00117)
		(width 0.20066)
		(layer "F.Cu")
		(net "M_C_CPU0_SA_DQS_DP<1>")
	)
	(segment
		(start 271.706086 -303.566576)
		(end 271.168114 -303.566576)
		(width 0.20066)
		(layer "F.Cu")
		(net "M_C_CPU0_SA_DQS_DP<1>")
	)
	(segment
		(start 279.816814 -303.566576)
		(end 278.711914 -303.566576)
		(width 0.20066)
		(layer "F.Cu")
		(net "M_C_CPU0_SA_DQS_DP<1>")
	)
	(segment
		(start 272.39214 -303.305464)
		(end 271.967198 -303.305464)
		(width 0.20066)
		(layer "F.Cu")
		(net "M_C_CPU0_SA_DQS_DP<1>")
	)
	(segment
		(start 278.163274 -303.566576)
		(end 277.902162 -303.305464)
		(width 0.20066)
		(layer "F.Cu")
		(net "M_C_CPU0_SA_DQS_DP<1>")
	)
	(segment
		(start 276.145752 -303.991772)
		(end 274.390358 -303.991772)
		(width 0.1016)
		(layer "F.Cu")
		(net "M_C_CPU0_SA_DQS_DP<1>")
	)
	(segment
		(start 271.967198 -303.305464)
		(end 271.706086 -303.566576)
		(width 0.20066)
		(layer "F.Cu")
		(net "M_C_CPU0_SA_DQS_DP<1>")
	)
	(segment
		(start 274.390358 -303.991772)
		(end 274.153376 -303.991772)
		(width 0.101854)
		(layer "F.Cu")
		(net "M_C_CPU0_SA_DQS_DP<1>")
	)
	(segment
		(start 278.711914 -303.566576)
		(end 278.163274 -303.566576)
		(width 0.20066)
		(layer "F.Cu")
		(net "M_C_CPU0_SA_DQS_DP<1>")
	)
	(segment
		(start 277.902162 -303.305464)
		(end 277.63343 -303.305464)
		(width 0.20066)
		(layer "F.Cu")
		(net "M_C_CPU0_SA_DQS_DP<1>")
	)
	(segment
		(start 277.208234 -303.73066)
		(end 276.882352 -303.73066)
		(width 0.20066)
		(layer "F.Cu")
		(net "M_C_CPU0_SA_DQS_DP<1>")
	)
	(segment
		(start 273.925792 -304.00117)
		(end 273.655282 -303.73066)
		(width 0.20066)
		(layer "F.Cu")
		(net "M_C_CPU0_SA_DQS_DP<1>")
	)
	(segment
		(start 274.153376 -303.991772)
		(end 274.143978 -304.00117)
		(width 0.101854)
		(layer "F.Cu")
		(net "M_C_CPU0_SA_DQS_DP<1>")
	)
	(segment
		(start 343.713562 -269.66164)
		(end 343.713816 -270.19758)
		(width 0.20066)
		(layer "F.Cu")
		(net "M_C_CPU0_SA_DQS_DP<1>")
	)
	(segment
		(start 276.882352 -303.73066)
		(end 276.62124 -303.991772)
		(width 0.20066)
		(layer "F.Cu")
		(net "M_C_CPU0_SA_DQS_DP<1>")
	)
	(segment
		(start 331.283056 -274.133056)
		(end 330.80452 -274.133056)
		(width 0.18288)
		(layer "In6.Cu")
		(net "M_C_CPU0_SA_DQS_DP<1>")
	)
	(segment
		(start 309.691532 -288.534094)
		(end 307.627274 -288.534094)
		(width 0.18288)
		(layer "In6.Cu")
		(net "M_C_CPU0_SA_DQS_DP<1>")
	)
	(segment
		(start 290.714684 -295.94683)
		(end 290.408106 -296.686986)
		(width 0.18288)
		(layer "In6.Cu")
		(net "M_C_CPU0_SA_DQS_DP<1>")
	)
	(segment
		(start 299.539152 -294.361362)
		(end 299.25899 -294.641524)
		(width 0.18288)
		(layer "In6.Cu")
		(net "M_C_CPU0_SA_DQS_DP<1>")
	)
	(segment
		(start 299.856652 -294.361362)
		(end 299.539152 -294.361362)
		(width 0.18288)
		(layer "In6.Cu")
		(net "M_C_CPU0_SA_DQS_DP<1>")
	)
	(segment
		(start 306.171092 -289.419538)
		(end 304.836576 -290.754054)
		(width 0.18288)
		(layer "In6.Cu")
		(net "M_C_CPU0_SA_DQS_DP<1>")
	)
	(segment
		(start 342.681814 -270.566642)
		(end 342.326214 -270.566642)
		(width 0.088646)
		(layer "In6.Cu")
		(net "M_C_CPU0_SA_DQS_DP<1>")
	)
	(segment
		(start 291.664898 -294.996616)
		(end 290.714684 -295.94683)
		(width 0.18288)
		(layer "In6.Cu")
		(net "M_C_CPU0_SA_DQS_DP<1>")
	)
	(segment
		(start 284.474158 -303.714912)
		(end 284.197298 -303.991772)
		(width 0.18288)
		(layer "In6.Cu")
		(net "M_C_CPU0_SA_DQS_DP<1>")
	)
	(segment
		(start 341.176864 -270.687038)
		(end 341.162132 -270.695674)
		(width 0.088646)
		(layer "In6.Cu")
		(net "M_C_CPU0_SA_DQS_DP<1>")
	)
	(segment
		(start 333.16672 -272.38325)
		(end 332.607412 -272.942558)
		(width 0.088646)
		(layer "In6.Cu")
		(net "M_C_CPU0_SA_DQS_DP<1>")
	)
	(segment
		(start 299.25899 -294.641524)
		(end 298.78147 -294.641524)
		(width 0.18288)
		(layer "In6.Cu")
		(net "M_C_CPU0_SA_DQS_DP<1>")
	)
	(segment
		(start 335.357724 -270.93672)
		(end 335.350612 -270.971518)
		(width 0.088646)
		(layer "In6.Cu")
		(net "M_C_CPU0_SA_DQS_DP<1>")
	)
	(segment
		(start 293.65321 -295.200832)
		(end 293.072312 -294.619934)
		(width 0.18288)
		(layer "In6.Cu")
		(net "M_C_CPU0_SA_DQS_DP<1>")
	)
	(segment
		(start 293.072312 -294.619934)
		(end 292.57244 -294.619934)
		(width 0.18288)
		(layer "In6.Cu")
		(net "M_C_CPU0_SA_DQS_DP<1>")
	)
	(segment
		(start 331.306424 -274.133056)
		(end 331.283056 -274.133056)
		(width 0.088646)
		(layer "In6.Cu")
		(net "M_C_CPU0_SA_DQS_DP<1>")
	)
	(segment
		(start 331.366368 -274.073112)
		(end 331.306424 -274.133056)
		(width 0.088646)
		(layer "In6.Cu")
		(net "M_C_CPU0_SA_DQS_DP<1>")
	)
	(segment
		(start 285.08706 -303.714912)
		(end 284.474158 -303.714912)
		(width 0.18288)
		(layer "In6.Cu")
		(net "M_C_CPU0_SA_DQS_DP<1>")
	)
	(segment
		(start 298.78147 -294.641524)
		(end 298.502578 -294.362632)
		(width 0.18288)
		(layer "In6.Cu")
		(net "M_C_CPU0_SA_DQS_DP<1>")
	)
	(segment
		(start 292.57244 -294.619934)
		(end 291.664898 -294.996616)
		(width 0.18288)
		(layer "In6.Cu")
		(net "M_C_CPU0_SA_DQS_DP<1>")
	)
	(segment
		(start 343.373456 -270.287496)
		(end 342.94826 -270.529304)
		(width 0.088646)
		(layer "In6.Cu")
		(net "M_C_CPU0_SA_DQS_DP<1>")
	)
	(segment
		(start 294.706548 -295.491916)
		(end 294.415464 -295.200832)
		(width 0.18288)
		(layer "In6.Cu")
		(net "M_C_CPU0_SA_DQS_DP<1>")
	)
	(segment
		(start 325.355712 -276.3901)
		(end 315.869828 -285.875984)
		(width 0.18288)
		(layer "In6.Cu")
		(net "M_C_CPU0_SA_DQS_DP<1>")
	)
	(segment
		(start 289.626294 -301.834296)
		(end 285.08706 -303.714912)
		(width 0.18288)
		(layer "In6.Cu")
		(net "M_C_CPU0_SA_DQS_DP<1>")
	)
	(segment
		(start 342.74379 -270.57096)
		(end 342.68664 -270.564102)
		(width 0.088646)
		(layer "In6.Cu")
		(net "M_C_CPU0_SA_DQS_DP<1>")
	)
	(segment
		(start 334.513428 -271.50695)
		(end 334.503014 -271.500854)
		(width 0.088646)
		(layer "In6.Cu")
		(net "M_C_CPU0_SA_DQS_DP<1>")
	)
	(segment
		(start 295.999916 -295.234868)
		(end 295.395904 -295.234868)
		(width 0.18288)
		(layer "In6.Cu")
		(net "M_C_CPU0_SA_DQS_DP<1>")
	)
	(segment
		(start 298.502578 -294.362632)
		(end 297.725084 -294.362632)
		(width 0.18288)
		(layer "In6.Cu")
		(net "M_C_CPU0_SA_DQS_DP<1>")
	)
	(segment
		(start 342.68664 -270.564102)
		(end 342.681814 -270.566642)
		(width 0.088646)
		(layer "In6.Cu")
		(net "M_C_CPU0_SA_DQS_DP<1>")
	)
	(segment
		(start 304.836576 -290.754054)
		(end 302.492918 -291.725096)
		(width 0.18288)
		(layer "In6.Cu")
		(net "M_C_CPU0_SA_DQS_DP<1>")
	)
	(segment
		(start 283.433266 -303.706276)
		(end 282.7401 -303.706276)
		(width 0.18288)
		(layer "In6.Cu")
		(net "M_C_CPU0_SA_DQS_DP<1>")
	)
	(segment
		(start 342.326214 -270.566642)
		(end 342.102694 -270.69542)
		(width 0.088646)
		(layer "In6.Cu")
		(net "M_C_CPU0_SA_DQS_DP<1>")
	)
	(segment
		(start 339.297264 -270.687038)
		(end 339.282532 -270.695674)
		(width 0.088646)
		(layer "In6.Cu")
		(net "M_C_CPU0_SA_DQS_DP<1>")
	)
	(segment
		(start 294.415464 -295.200832)
		(end 293.65321 -295.200832)
		(width 0.18288)
		(layer "In6.Cu")
		(net "M_C_CPU0_SA_DQS_DP<1>")
	)
	(segment
		(start 312.24982 -287.47466)
		(end 309.691532 -288.534094)
		(width 0.18288)
		(layer "In6.Cu")
		(net "M_C_CPU0_SA_DQS_DP<1>")
	)
	(segment
		(start 283.718762 -303.991772)
		(end 283.433266 -303.706276)
		(width 0.18288)
		(layer "In6.Cu")
		(net "M_C_CPU0_SA_DQS_DP<1>")
	)
	(segment
		(start 280.085546 -303.297844)
		(end 279.816814 -303.566576)
		(width 0.18288)
		(layer "In6.Cu")
		(net "M_C_CPU0_SA_DQS_DP<1>")
	)
	(segment
		(start 333.941166 -271.825212)
		(end 333.941166 -271.840706)
		(width 0.088646)
		(layer "In6.Cu")
		(net "M_C_CPU0_SA_DQS_DP<1>")
	)
	(segment
		(start 282.359862 -303.32553)
		(end 281.830272 -303.106836)
		(width 0.18288)
		(layer "In6.Cu")
		(net "M_C_CPU0_SA_DQS_DP<1>")
	)
	(segment
		(start 297.725084 -294.362632)
		(end 297.118278 -294.969438)
		(width 0.18288)
		(layer "In6.Cu")
		(net "M_C_CPU0_SA_DQS_DP<1>")
	)
	(segment
		(start 282.7401 -303.706276)
		(end 282.359862 -303.32553)
		(width 0.18288)
		(layer "In6.Cu")
		(net "M_C_CPU0_SA_DQS_DP<1>")
	)
	(segment
		(start 313.848496 -285.875984)
		(end 312.24982 -287.47466)
		(width 0.18288)
		(layer "In6.Cu")
		(net "M_C_CPU0_SA_DQS_DP<1>")
	)
	(segment
		(start 332.607412 -272.942558)
		(end 332.607412 -273.417284)
		(width 0.088646)
		(layer "In6.Cu")
		(net "M_C_CPU0_SA_DQS_DP<1>")
	)
	(segment
		(start 333.400146 -272.38325)
		(end 333.16672 -272.38325)
		(width 0.088646)
		(layer "In6.Cu")
		(net "M_C_CPU0_SA_DQS_DP<1>")
	)
	(segment
		(start 297.118278 -294.969438)
		(end 296.265346 -294.969438)
		(width 0.18288)
		(layer "In6.Cu")
		(net "M_C_CPU0_SA_DQS_DP<1>")
	)
	(segment
		(start 302.492918 -291.725096)
		(end 299.856652 -294.361362)
		(width 0.18288)
		(layer "In6.Cu")
		(net "M_C_CPU0_SA_DQS_DP<1>")
	)
	(segment
		(start 307.145436 -289.015932)
		(end 306.171092 -289.419538)
		(width 0.18288)
		(layer "In6.Cu")
		(net "M_C_CPU0_SA_DQS_DP<1>")
	)
	(segment
		(start 295.395904 -295.234868)
		(end 295.138856 -295.491916)
		(width 0.18288)
		(layer "In6.Cu")
		(net "M_C_CPU0_SA_DQS_DP<1>")
	)
	(segment
		(start 296.265346 -294.969438)
		(end 295.999916 -295.234868)
		(width 0.18288)
		(layer "In6.Cu")
		(net "M_C_CPU0_SA_DQS_DP<1>")
	)
	(segment
		(start 290.408106 -296.686986)
		(end 290.408106 -301.052484)
		(width 0.18288)
		(layer "In6.Cu")
		(net "M_C_CPU0_SA_DQS_DP<1>")
	)
	(segment
		(start 334.128618 -271.500854)
		(end 334.119728 -271.505934)
		(width 0.088646)
		(layer "In6.Cu")
		(net "M_C_CPU0_SA_DQS_DP<1>")
	)
	(segment
		(start 284.197298 -303.991772)
		(end 283.718762 -303.991772)
		(width 0.18288)
		(layer "In6.Cu")
		(net "M_C_CPU0_SA_DQS_DP<1>")
	)
	(segment
		(start 341.551514 -270.687038)
		(end 341.55126 -270.687038)
		(width 0.088646)
		(layer "In6.Cu")
		(net "M_C_CPU0_SA_DQS_DP<1>")
	)
	(segment
		(start 331.951584 -274.073112)
		(end 331.366368 -274.073112)
		(width 0.088646)
		(layer "In6.Cu")
		(net "M_C_CPU0_SA_DQS_DP<1>")
	)
	(segment
		(start 335.350612 -270.971518)
		(end 335.350612 -271.021302)
		(width 0.088646)
		(layer "In6.Cu")
		(net "M_C_CPU0_SA_DQS_DP<1>")
	)
	(segment
		(start 307.627274 -288.534094)
		(end 307.145436 -289.015932)
		(width 0.18288)
		(layer "In6.Cu")
		(net "M_C_CPU0_SA_DQS_DP<1>")
	)
	(segment
		(start 295.138856 -295.491916)
		(end 294.706548 -295.491916)
		(width 0.18288)
		(layer "In6.Cu")
		(net "M_C_CPU0_SA_DQS_DP<1>")
	)
	(segment
		(start 290.408106 -301.052484)
		(end 289.626294 -301.834296)
		(width 0.18288)
		(layer "In6.Cu")
		(net "M_C_CPU0_SA_DQS_DP<1>")
	)
	(segment
		(start 281.830272 -303.106836)
		(end 281.351228 -303.106836)
		(width 0.18288)
		(layer "In6.Cu")
		(net "M_C_CPU0_SA_DQS_DP<1>")
	)
	(segment
		(start 330.80452 -274.133056)
		(end 325.355712 -276.3901)
		(width 0.18288)
		(layer "In6.Cu")
		(net "M_C_CPU0_SA_DQS_DP<1>")
	)
	(segment
		(start 280.889964 -303.297844)
		(end 280.085546 -303.297844)
		(width 0.18288)
		(layer "In6.Cu")
		(net "M_C_CPU0_SA_DQS_DP<1>")
	)
	(segment
		(start 281.351228 -303.106836)
		(end 280.889964 -303.297844)
		(width 0.18288)
		(layer "In6.Cu")
		(net "M_C_CPU0_SA_DQS_DP<1>")
	)
	(segment
		(start 315.869828 -285.875984)
		(end 313.848496 -285.875984)
		(width 0.18288)
		(layer "In6.Cu")
		(net "M_C_CPU0_SA_DQS_DP<1>")
	)
	(segment
		(start 332.607412 -273.417284)
		(end 331.951584 -274.073112)
		(width 0.088646)
		(layer "In6.Cu")
		(net "M_C_CPU0_SA_DQS_DP<1>")
	)
	(arc
		(start 336.477864 -270.687038)
		(mid 336.195162 -270.762814)
		(end 335.91246 -270.687038)
		(width 0.088646)
		(layer "In6.Cu")
		(net "M_C_CPU0_SA_DQS_DP<1>")
	)
	(arc
		(start 339.282532 -270.695674)
		(mid 339.006057 -270.762994)
		(end 338.73186 -270.687038)
		(width 0.088646)
		(layer "In6.Cu")
		(net "M_C_CPU0_SA_DQS_DP<1>")
	)
	(arc
		(start 339.67166 -270.687038)
		(mid 339.484462 -270.636895)
		(end 339.297264 -270.687038)
		(width 0.088646)
		(layer "In6.Cu")
		(net "M_C_CPU0_SA_DQS_DP<1>")
	)
	(arc
		(start 335.91246 -270.687038)
		(mid 335.571157 -270.66983)
		(end 335.357724 -270.93672)
		(width 0.088646)
		(layer "In6.Cu")
		(net "M_C_CPU0_SA_DQS_DP<1>")
	)
	(arc
		(start 337.417664 -270.687038)
		(mid 337.134962 -270.762814)
		(end 336.85226 -270.687038)
		(width 0.088646)
		(layer "In6.Cu")
		(net "M_C_CPU0_SA_DQS_DP<1>")
	)
	(arc
		(start 340.61146 -270.687038)
		(mid 340.424262 -270.636895)
		(end 340.237064 -270.687038)
		(width 0.088646)
		(layer "In6.Cu")
		(net "M_C_CPU0_SA_DQS_DP<1>")
	)
	(arc
		(start 341.55126 -270.687038)
		(mid 341.364062 -270.636895)
		(end 341.176864 -270.687038)
		(width 0.088646)
		(layer "In6.Cu")
		(net "M_C_CPU0_SA_DQS_DP<1>")
	)
	(arc
		(start 342.94826 -270.529304)
		(mid 342.849418 -270.566814)
		(end 342.74379 -270.57096)
		(width 0.088646)
		(layer "In6.Cu")
		(net "M_C_CPU0_SA_DQS_DP<1>")
	)
	(arc
		(start 337.79206 -270.687038)
		(mid 337.604862 -270.636895)
		(end 337.417664 -270.687038)
		(width 0.088646)
		(layer "In6.Cu")
		(net "M_C_CPU0_SA_DQS_DP<1>")
	)
	(arc
		(start 341.162132 -270.695674)
		(mid 340.885657 -270.762994)
		(end 340.61146 -270.687038)
		(width 0.088646)
		(layer "In6.Cu")
		(net "M_C_CPU0_SA_DQS_DP<1>")
	)
	(arc
		(start 340.237064 -270.687038)
		(mid 339.954362 -270.762814)
		(end 339.67166 -270.687038)
		(width 0.088646)
		(layer "In6.Cu")
		(net "M_C_CPU0_SA_DQS_DP<1>")
	)
	(arc
		(start 336.85226 -270.687038)
		(mid 336.665062 -270.636895)
		(end 336.477864 -270.687038)
		(width 0.088646)
		(layer "In6.Cu")
		(net "M_C_CPU0_SA_DQS_DP<1>")
	)
	(arc
		(start 333.671926 -272.306542)
		(mid 333.541361 -272.363758)
		(end 333.400146 -272.38325)
		(width 0.088646)
		(layer "In6.Cu")
		(net "M_C_CPU0_SA_DQS_DP<1>")
	)
	(arc
		(start 342.102694 -270.69542)
		(mid 341.826029 -270.762891)
		(end 341.551514 -270.687038)
		(width 0.088646)
		(layer "In6.Cu")
		(net "M_C_CPU0_SA_DQS_DP<1>")
	)
	(arc
		(start 335.068164 -271.500854)
		(mid 334.791605 -271.576597)
		(end 334.513428 -271.50695)
		(width 0.088646)
		(layer "In6.Cu")
		(net "M_C_CPU0_SA_DQS_DP<1>")
	)
	(arc
		(start 335.350612 -271.021302)
		(mid 335.272501 -271.298251)
		(end 335.068164 -271.500854)
		(width 0.088646)
		(layer "In6.Cu")
		(net "M_C_CPU0_SA_DQS_DP<1>")
	)
	(arc
		(start 334.503014 -271.500854)
		(mid 334.315816 -271.450711)
		(end 334.128618 -271.500854)
		(width 0.088646)
		(layer "In6.Cu")
		(net "M_C_CPU0_SA_DQS_DP<1>")
	)
	(arc
		(start 338.357464 -270.687038)
		(mid 338.074762 -270.762814)
		(end 337.79206 -270.687038)
		(width 0.088646)
		(layer "In6.Cu")
		(net "M_C_CPU0_SA_DQS_DP<1>")
	)
	(arc
		(start 343.713816 -270.19758)
		(mid 343.537795 -270.220417)
		(end 343.373456 -270.287496)
		(width 0.088646)
		(layer "In6.Cu")
		(net "M_C_CPU0_SA_DQS_DP<1>")
	)
	(arc
		(start 333.941166 -271.840706)
		(mid 333.865551 -272.10773)
		(end 333.671926 -272.306542)
		(width 0.088646)
		(layer "In6.Cu")
		(net "M_C_CPU0_SA_DQS_DP<1>")
	)
	(arc
		(start 338.73186 -270.687038)
		(mid 338.544662 -270.636895)
		(end 338.357464 -270.687038)
		(width 0.088646)
		(layer "In6.Cu")
		(net "M_C_CPU0_SA_DQS_DP<1>")
	)
	(arc
		(start 334.119728 -271.505934)
		(mid 333.988814 -271.642294)
		(end 333.941166 -271.825212)
		(width 0.088646)
		(layer "In6.Cu")
		(net "M_C_CPU0_SA_DQS_DP<1>")
	)
	(segment
		(start 340.424516 -277.522178)
		(end 340.424262 -277.522432)
		(width 0.20066)
		(layer "F.Cu")
		(net "M_C_CPU0_SA_DQS_DP<0>")
	)
	(segment
		(start 279.816814 -312.91657)
		(end 278.711914 -312.91657)
		(width 0.20066)
		(layer "F.Cu")
		(net "M_C_CPU0_SA_DQS_DP<0>")
	)
	(segment
		(start 276.882352 -313.080654)
		(end 276.62124 -313.341766)
		(width 0.20066)
		(layer "F.Cu")
		(net "M_C_CPU0_SA_DQS_DP<0>")
	)
	(segment
		(start 340.424516 -276.986492)
		(end 340.424516 -277.522178)
		(width 0.20066)
		(layer "F.Cu")
		(net "M_C_CPU0_SA_DQS_DP<0>")
	)
	(segment
		(start 276.145752 -313.341766)
		(end 274.390358 -313.341766)
		(width 0.1016)
		(layer "F.Cu")
		(net "M_C_CPU0_SA_DQS_DP<0>")
	)
	(segment
		(start 277.63343 -312.655458)
		(end 277.208234 -313.080654)
		(width 0.20066)
		(layer "F.Cu")
		(net "M_C_CPU0_SA_DQS_DP<0>")
	)
	(segment
		(start 274.390358 -313.341766)
		(end 274.153376 -313.341766)
		(width 0.101854)
		(layer "F.Cu")
		(net "M_C_CPU0_SA_DQS_DP<0>")
	)
	(segment
		(start 276.469094 -313.341766)
		(end 276.145752 -313.341766)
		(width 0.101854)
		(layer "F.Cu")
		(net "M_C_CPU0_SA_DQS_DP<0>")
	)
	(segment
		(start 273.655282 -313.080654)
		(end 273.028156 -313.080654)
		(width 0.20066)
		(layer "F.Cu")
		(net "M_C_CPU0_SA_DQS_DP<0>")
	)
	(segment
		(start 271.706086 -312.91657)
		(end 271.168114 -312.91657)
		(width 0.20066)
		(layer "F.Cu")
		(net "M_C_CPU0_SA_DQS_DP<0>")
	)
	(segment
		(start 274.143978 -313.351164)
		(end 273.925792 -313.351164)
		(width 0.20066)
		(layer "F.Cu")
		(net "M_C_CPU0_SA_DQS_DP<0>")
	)
	(segment
		(start 272.39214 -312.655458)
		(end 271.967198 -312.655458)
		(width 0.20066)
		(layer "F.Cu")
		(net "M_C_CPU0_SA_DQS_DP<0>")
	)
	(segment
		(start 278.163274 -312.91657)
		(end 277.902162 -312.655458)
		(width 0.20066)
		(layer "F.Cu")
		(net "M_C_CPU0_SA_DQS_DP<0>")
	)
	(segment
		(start 277.902162 -312.655458)
		(end 277.63343 -312.655458)
		(width 0.20066)
		(layer "F.Cu")
		(net "M_C_CPU0_SA_DQS_DP<0>")
	)
	(segment
		(start 273.028156 -313.080654)
		(end 272.39214 -312.655458)
		(width 0.20066)
		(layer "F.Cu")
		(net "M_C_CPU0_SA_DQS_DP<0>")
	)
	(segment
		(start 276.62124 -313.341766)
		(end 276.469094 -313.341766)
		(width 0.20066)
		(layer "F.Cu")
		(net "M_C_CPU0_SA_DQS_DP<0>")
	)
	(segment
		(start 274.153376 -313.341766)
		(end 274.143978 -313.351164)
		(width 0.101854)
		(layer "F.Cu")
		(net "M_C_CPU0_SA_DQS_DP<0>")
	)
	(segment
		(start 278.711914 -312.91657)
		(end 278.163274 -312.91657)
		(width 0.20066)
		(layer "F.Cu")
		(net "M_C_CPU0_SA_DQS_DP<0>")
	)
	(segment
		(start 277.208234 -313.080654)
		(end 276.882352 -313.080654)
		(width 0.20066)
		(layer "F.Cu")
		(net "M_C_CPU0_SA_DQS_DP<0>")
	)
	(segment
		(start 273.925792 -313.351164)
		(end 273.655282 -313.080654)
		(width 0.20066)
		(layer "F.Cu")
		(net "M_C_CPU0_SA_DQS_DP<0>")
	)
	(segment
		(start 271.967198 -312.655458)
		(end 271.706086 -312.91657)
		(width 0.20066)
		(layer "F.Cu")
		(net "M_C_CPU0_SA_DQS_DP<0>")
	)
	(segment
		(start 338.361274 -279.476962)
		(end 338.369656 -279.481788)
		(width 0.088646)
		(layer "In4.Cu")
		(net "M_C_CPU0_SA_DQS_DP<0>")
	)
	(segment
		(start 339.397086 -277.888954)
		(end 339.39226 -277.891494)
		(width 0.088646)
		(layer "In4.Cu")
		(net "M_C_CPU0_SA_DQS_DP<0>")
	)
	(segment
		(start 294.434768 -315.61532)
		(end 293.845488 -315.61532)
		(width 0.18288)
		(layer "In4.Cu")
		(net "M_C_CPU0_SA_DQS_DP<0>")
	)
	(segment
		(start 336.477102 -283.709872)
		(end 336.469228 -283.714444)
		(width 0.088646)
		(layer "In4.Cu")
		(net "M_C_CPU0_SA_DQS_DP<0>")
	)
	(segment
		(start 336.947764 -282.895548)
		(end 336.938874 -282.900628)
		(width 0.088646)
		(layer "In4.Cu")
		(net "M_C_CPU0_SA_DQS_DP<0>")
	)
	(segment
		(start 298.519342 -314.749688)
		(end 297.95216 -314.749688)
		(width 0.18288)
		(layer "In4.Cu")
		(net "M_C_CPU0_SA_DQS_DP<0>")
	)
	(segment
		(start 298.811442 -315.041788)
		(end 298.519342 -314.749688)
		(width 0.18288)
		(layer "In4.Cu")
		(net "M_C_CPU0_SA_DQS_DP<0>")
	)
	(segment
		(start 339.454236 -277.895812)
		(end 339.397086 -277.888954)
		(width 0.088646)
		(layer "In4.Cu")
		(net "M_C_CPU0_SA_DQS_DP<0>")
	)
	(segment
		(start 338.170012 -280.778204)
		(end 338.170012 -280.78811)
		(width 0.088646)
		(layer "In4.Cu")
		(net "M_C_CPU0_SA_DQS_DP<0>")
	)
	(segment
		(start 338.640166 -279.964134)
		(end 338.640166 -279.971754)
		(width 0.088646)
		(layer "In4.Cu")
		(net "M_C_CPU0_SA_DQS_DP<0>")
	)
	(segment
		(start 335.820512 -284.847538)
		(end 335.820512 -284.857444)
		(width 0.088646)
		(layer "In4.Cu")
		(net "M_C_CPU0_SA_DQS_DP<0>")
	)
	(segment
		(start 339.39226 -277.891494)
		(end 339.342222 -277.891494)
		(width 0.088646)
		(layer "In4.Cu")
		(net "M_C_CPU0_SA_DQS_DP<0>")
	)
	(segment
		(start 287.28543 -313.07532)
		(end 284.380432 -313.07532)
		(width 0.18288)
		(layer "In4.Cu")
		(net "M_C_CPU0_SA_DQS_DP<0>")
	)
	(segment
		(start 336.007964 -284.52318)
		(end 335.999074 -284.52826)
		(width 0.088646)
		(layer "In4.Cu")
		(net "M_C_CPU0_SA_DQS_DP<0>")
	)
	(segment
		(start 284.113986 -313.341766)
		(end 283.723334 -313.341766)
		(width 0.18288)
		(layer "In4.Cu")
		(net "M_C_CPU0_SA_DQS_DP<0>")
	)
	(segment
		(start 284.380432 -313.07532)
		(end 284.113986 -313.341766)
		(width 0.18288)
		(layer "In4.Cu")
		(net "M_C_CPU0_SA_DQS_DP<0>")
	)
	(segment
		(start 282.810966 -313.056524)
		(end 282.192984 -312.438542)
		(width 0.18288)
		(layer "In4.Cu")
		(net "M_C_CPU0_SA_DQS_DP<0>")
	)
	(segment
		(start 332.320646 -286.512)
		(end 330.406502 -288.426398)
		(width 0.18288)
		(layer "In4.Cu")
		(net "M_C_CPU0_SA_DQS_DP<0>")
	)
	(segment
		(start 338.356702 -278.826468)
		(end 338.348574 -278.83104)
		(width 0.088646)
		(layer "In4.Cu")
		(net "M_C_CPU0_SA_DQS_DP<0>")
	)
	(segment
		(start 303.076356 -314.766198)
		(end 299.480732 -314.766198)
		(width 0.18288)
		(layer "In4.Cu")
		(net "M_C_CPU0_SA_DQS_DP<0>")
	)
	(segment
		(start 319.85077 -306.246022)
		(end 314.812934 -311.284112)
		(width 0.18288)
		(layer "In4.Cu")
		(net "M_C_CPU0_SA_DQS_DP<0>")
	)
	(segment
		(start 280.525728 -312.640726)
		(end 280.092658 -312.640726)
		(width 0.18288)
		(layer "In4.Cu")
		(net "M_C_CPU0_SA_DQS_DP<0>")
	)
	(segment
		(start 299.205142 -315.041788)
		(end 298.811442 -315.041788)
		(width 0.18288)
		(layer "In4.Cu")
		(net "M_C_CPU0_SA_DQS_DP<0>")
	)
	(segment
		(start 280.727912 -312.438542)
		(end 280.525728 -312.640726)
		(width 0.18288)
		(layer "In4.Cu")
		(net "M_C_CPU0_SA_DQS_DP<0>")
	)
	(segment
		(start 337.887564 -282.895548)
		(end 337.872832 -282.904184)
		(width 0.088646)
		(layer "In4.Cu")
		(net "M_C_CPU0_SA_DQS_DP<0>")
	)
	(segment
		(start 338.357464 -279.474676)
		(end 338.361274 -279.476962)
		(width 0.088646)
		(layer "In4.Cu")
		(net "M_C_CPU0_SA_DQS_DP<0>")
	)
	(segment
		(start 306.589684 -312.25363)
		(end 304.865278 -313.978036)
		(width 0.18288)
		(layer "In4.Cu")
		(net "M_C_CPU0_SA_DQS_DP<0>")
	)
	(segment
		(start 326.62368 -297.55719)
		(end 319.85077 -304.3301)
		(width 0.18288)
		(layer "In4.Cu")
		(net "M_C_CPU0_SA_DQS_DP<0>")
	)
	(segment
		(start 332.548738 -286.512)
		(end 332.320646 -286.512)
		(width 0.18288)
		(layer "In4.Cu")
		(net "M_C_CPU0_SA_DQS_DP<0>")
	)
	(segment
		(start 312.471816 -312.25363)
		(end 306.589684 -312.25363)
		(width 0.18288)
		(layer "In4.Cu")
		(net "M_C_CPU0_SA_DQS_DP<0>")
	)
	(segment
		(start 319.85077 -304.3301)
		(end 319.85077 -306.246022)
		(width 0.18288)
		(layer "In4.Cu")
		(net "M_C_CPU0_SA_DQS_DP<0>")
	)
	(segment
		(start 293.845488 -315.61532)
		(end 293.314882 -315.084714)
		(width 0.18288)
		(layer "In4.Cu")
		(net "M_C_CPU0_SA_DQS_DP<0>")
	)
	(segment
		(start 333.582772 -285.3944)
		(end 333.400908 -285.575756)
		(width 0.088646)
		(layer "In4.Cu")
		(net "M_C_CPU0_SA_DQS_DP<0>")
	)
	(segment
		(start 338.348574 -279.469596)
		(end 338.356702 -279.474168)
		(width 0.088646)
		(layer "In4.Cu")
		(net "M_C_CPU0_SA_DQS_DP<0>")
	)
	(segment
		(start 292.532308 -314.760356)
		(end 291.73551 -313.963812)
		(width 0.18288)
		(layer "In4.Cu")
		(net "M_C_CPU0_SA_DQS_DP<0>")
	)
	(segment
		(start 289.429444 -313.963812)
		(end 287.28543 -313.07532)
		(width 0.18288)
		(layer "In4.Cu")
		(net "M_C_CPU0_SA_DQS_DP<0>")
	)
	(segment
		(start 340.083902 -277.612348)
		(end 339.658706 -277.854156)
		(width 0.088646)
		(layer "In4.Cu")
		(net "M_C_CPU0_SA_DQS_DP<0>")
	)
	(segment
		(start 338.357464 -278.82596)
		(end 338.356702 -278.826468)
		(width 0.088646)
		(layer "In4.Cu")
		(net "M_C_CPU0_SA_DQS_DP<0>")
	)
	(segment
		(start 297.09491 -315.606938)
		(end 295.37533 -315.606938)
		(width 0.18288)
		(layer "In4.Cu")
		(net "M_C_CPU0_SA_DQS_DP<0>")
	)
	(segment
		(start 340.424262 -277.522432)
		(end 340.301072 -277.522432)
		(width 0.088646)
		(layer "In4.Cu")
		(net "M_C_CPU0_SA_DQS_DP<0>")
	)
	(segment
		(start 303.864518 -313.978036)
		(end 303.076356 -314.766198)
		(width 0.18288)
		(layer "In4.Cu")
		(net "M_C_CPU0_SA_DQS_DP<0>")
	)
	(segment
		(start 283.723334 -313.341766)
		(end 283.438092 -313.056524)
		(width 0.18288)
		(layer "In4.Cu")
		(net "M_C_CPU0_SA_DQS_DP<0>")
	)
	(segment
		(start 299.480732 -314.766198)
		(end 299.205142 -315.041788)
		(width 0.18288)
		(layer "In4.Cu")
		(net "M_C_CPU0_SA_DQS_DP<0>")
	)
	(segment
		(start 338.357464 -280.453846)
		(end 338.348574 -280.458926)
		(width 0.088646)
		(layer "In4.Cu")
		(net "M_C_CPU0_SA_DQS_DP<0>")
	)
	(segment
		(start 291.73551 -313.963812)
		(end 289.429444 -313.963812)
		(width 0.18288)
		(layer "In4.Cu")
		(net "M_C_CPU0_SA_DQS_DP<0>")
	)
	(segment
		(start 333.112872 -285.863792)
		(end 333.112872 -285.947866)
		(width 0.088646)
		(layer "In4.Cu")
		(net "M_C_CPU0_SA_DQS_DP<0>")
	)
	(segment
		(start 282.192984 -312.438542)
		(end 280.727912 -312.438542)
		(width 0.18288)
		(layer "In4.Cu")
		(net "M_C_CPU0_SA_DQS_DP<0>")
	)
	(segment
		(start 295.37533 -315.606938)
		(end 295.090342 -315.891926)
		(width 0.18288)
		(layer "In4.Cu")
		(net "M_C_CPU0_SA_DQS_DP<0>")
	)
	(segment
		(start 337.887564 -281.916378)
		(end 337.888326 -281.916886)
		(width 0.088646)
		(layer "In4.Cu")
		(net "M_C_CPU0_SA_DQS_DP<0>")
	)
	(segment
		(start 293.314882 -315.084714)
		(end 292.532308 -314.760356)
		(width 0.18288)
		(layer "In4.Cu")
		(net "M_C_CPU0_SA_DQS_DP<0>")
	)
	(segment
		(start 338.356702 -279.474168)
		(end 338.357464 -279.474676)
		(width 0.088646)
		(layer "In4.Cu")
		(net "M_C_CPU0_SA_DQS_DP<0>")
	)
	(segment
		(start 338.639912 -278.336502)
		(end 338.639912 -278.346408)
		(width 0.088646)
		(layer "In4.Cu")
		(net "M_C_CPU0_SA_DQS_DP<0>")
	)
	(segment
		(start 294.711374 -315.891926)
		(end 294.434768 -315.61532)
		(width 0.18288)
		(layer "In4.Cu")
		(net "M_C_CPU0_SA_DQS_DP<0>")
	)
	(segment
		(start 336.760312 -283.219906)
		(end 336.760312 -283.2354)
		(width 0.088646)
		(layer "In4.Cu")
		(net "M_C_CPU0_SA_DQS_DP<0>")
	)
	(segment
		(start 295.090342 -315.891926)
		(end 294.711374 -315.891926)
		(width 0.18288)
		(layer "In4.Cu")
		(net "M_C_CPU0_SA_DQS_DP<0>")
	)
	(segment
		(start 333.078328 -285.98241)
		(end 332.548738 -286.512)
		(width 0.18288)
		(layer "In4.Cu")
		(net "M_C_CPU0_SA_DQS_DP<0>")
	)
	(segment
		(start 314.812934 -311.284112)
		(end 312.471816 -312.25363)
		(width 0.18288)
		(layer "In4.Cu")
		(net "M_C_CPU0_SA_DQS_DP<0>")
	)
	(segment
		(start 333.400908 -285.575756)
		(end 333.112872 -285.863792)
		(width 0.088646)
		(layer "In4.Cu")
		(net "M_C_CPU0_SA_DQS_DP<0>")
	)
	(segment
		(start 336.478118 -283.709364)
		(end 336.477102 -283.709872)
		(width 0.088646)
		(layer "In4.Cu")
		(net "M_C_CPU0_SA_DQS_DP<0>")
	)
	(segment
		(start 337.888326 -281.916886)
		(end 337.89366 -281.919934)
		(width 0.088646)
		(layer "In4.Cu")
		(net "M_C_CPU0_SA_DQS_DP<0>")
	)
	(segment
		(start 333.112872 -285.947866)
		(end 333.078328 -285.98241)
		(width 0.088646)
		(layer "In4.Cu")
		(net "M_C_CPU0_SA_DQS_DP<0>")
	)
	(segment
		(start 336.020156 -284.516068)
		(end 336.009234 -284.522418)
		(width 0.088646)
		(layer "In4.Cu")
		(net "M_C_CPU0_SA_DQS_DP<0>")
	)
	(segment
		(start 338.170266 -282.405836)
		(end 338.170266 -282.42006)
		(width 0.088646)
		(layer "In4.Cu")
		(net "M_C_CPU0_SA_DQS_DP<0>")
	)
	(segment
		(start 304.865278 -313.978036)
		(end 303.864518 -313.978036)
		(width 0.18288)
		(layer "In4.Cu")
		(net "M_C_CPU0_SA_DQS_DP<0>")
	)
	(segment
		(start 330.406502 -288.426398)
		(end 326.62368 -297.55719)
		(width 0.18288)
		(layer "In4.Cu")
		(net "M_C_CPU0_SA_DQS_DP<0>")
	)
	(segment
		(start 280.092658 -312.640726)
		(end 279.816814 -312.91657)
		(width 0.18288)
		(layer "In4.Cu")
		(net "M_C_CPU0_SA_DQS_DP<0>")
	)
	(segment
		(start 338.827364 -278.012144)
		(end 338.818474 -278.017224)
		(width 0.088646)
		(layer "In4.Cu")
		(net "M_C_CPU0_SA_DQS_DP<0>")
	)
	(segment
		(start 283.438092 -313.056524)
		(end 282.810966 -313.056524)
		(width 0.18288)
		(layer "In4.Cu")
		(net "M_C_CPU0_SA_DQS_DP<0>")
	)
	(segment
		(start 336.009234 -284.522418)
		(end 336.007964 -284.52318)
		(width 0.088646)
		(layer "In4.Cu")
		(net "M_C_CPU0_SA_DQS_DP<0>")
	)
	(segment
		(start 297.95216 -314.749688)
		(end 297.09491 -315.606938)
		(width 0.18288)
		(layer "In4.Cu")
		(net "M_C_CPU0_SA_DQS_DP<0>")
	)
	(arc
		(start 334.033368 -285.336742)
		(mid 333.967667 -285.306945)
		(end 333.897478 -285.29026)
		(width 0.088646)
		(layer "In4.Cu")
		(net "M_C_CPU0_SA_DQS_DP<0>")
	)
	(arc
		(start 339.342222 -277.891494)
		(mid 339.266823 -277.905185)
		(end 339.19033 -277.909782)
		(width 0.088646)
		(layer "In4.Cu")
		(net "M_C_CPU0_SA_DQS_DP<0>")
	)
	(arc
		(start 333.897478 -285.29026)
		(mid 333.77382 -285.293441)
		(end 333.657956 -285.336742)
		(width 0.088646)
		(layer "In4.Cu")
		(net "M_C_CPU0_SA_DQS_DP<0>")
	)
	(arc
		(start 340.301072 -277.522432)
		(mid 340.183555 -277.545808)
		(end 340.083902 -277.612348)
		(width 0.088646)
		(layer "In4.Cu")
		(net "M_C_CPU0_SA_DQS_DP<0>")
	)
	(arc
		(start 338.369656 -279.481788)
		(mid 338.567884 -279.687636)
		(end 338.640166 -279.964134)
		(width 0.088646)
		(layer "In4.Cu")
		(net "M_C_CPU0_SA_DQS_DP<0>")
	)
	(arc
		(start 338.170266 -282.42006)
		(mid 338.091047 -282.694745)
		(end 337.887564 -282.895548)
		(width 0.088646)
		(layer "In4.Cu")
		(net "M_C_CPU0_SA_DQS_DP<0>")
	)
	(arc
		(start 333.657956 -285.336742)
		(mid 333.618474 -285.363107)
		(end 333.582772 -285.3944)
		(width 0.088646)
		(layer "In4.Cu")
		(net "M_C_CPU0_SA_DQS_DP<0>")
	)
	(arc
		(start 334.598264 -285.336996)
		(mid 334.315787 -285.412518)
		(end 334.033368 -285.336742)
		(width 0.088646)
		(layer "In4.Cu")
		(net "M_C_CPU0_SA_DQS_DP<0>")
	)
	(arc
		(start 337.32216 -282.895548)
		(mid 337.134962 -282.845405)
		(end 336.947764 -282.895548)
		(width 0.088646)
		(layer "In4.Cu")
		(net "M_C_CPU0_SA_DQS_DP<0>")
	)
	(arc
		(start 337.872832 -282.904184)
		(mid 337.596391 -282.97135)
		(end 337.32216 -282.895548)
		(width 0.088646)
		(layer "In4.Cu")
		(net "M_C_CPU0_SA_DQS_DP<0>")
	)
	(arc
		(start 336.469228 -283.714444)
		(mid 336.338314 -283.850804)
		(end 336.290666 -284.033722)
		(width 0.088646)
		(layer "In4.Cu")
		(net "M_C_CPU0_SA_DQS_DP<0>")
	)
	(arc
		(start 335.820512 -284.857444)
		(mid 335.742401 -285.134393)
		(end 335.538064 -285.336996)
		(width 0.088646)
		(layer "In4.Cu")
		(net "M_C_CPU0_SA_DQS_DP<0>")
	)
	(arc
		(start 338.348574 -280.458926)
		(mid 338.21766 -280.595286)
		(end 338.170012 -280.778204)
		(width 0.088646)
		(layer "In4.Cu")
		(net "M_C_CPU0_SA_DQS_DP<0>")
	)
	(arc
		(start 337.887564 -281.267662)
		(mid 337.700388 -281.59202)
		(end 337.887564 -281.916378)
		(width 0.088646)
		(layer "In4.Cu")
		(net "M_C_CPU0_SA_DQS_DP<0>")
	)
	(arc
		(start 336.938874 -282.900628)
		(mid 336.80796 -283.036988)
		(end 336.760312 -283.219906)
		(width 0.088646)
		(layer "In4.Cu")
		(net "M_C_CPU0_SA_DQS_DP<0>")
	)
	(arc
		(start 335.999074 -284.52826)
		(mid 335.86816 -284.66462)
		(end 335.820512 -284.847538)
		(width 0.088646)
		(layer "In4.Cu")
		(net "M_C_CPU0_SA_DQS_DP<0>")
	)
	(arc
		(start 338.818474 -278.017224)
		(mid 338.68756 -278.153584)
		(end 338.639912 -278.336502)
		(width 0.088646)
		(layer "In4.Cu")
		(net "M_C_CPU0_SA_DQS_DP<0>")
	)
	(arc
		(start 339.658706 -277.854156)
		(mid 339.559864 -277.891666)
		(end 339.454236 -277.895812)
		(width 0.088646)
		(layer "In4.Cu")
		(net "M_C_CPU0_SA_DQS_DP<0>")
	)
	(arc
		(start 334.97266 -285.336996)
		(mid 334.785462 -285.286853)
		(end 334.598264 -285.336996)
		(width 0.088646)
		(layer "In4.Cu")
		(net "M_C_CPU0_SA_DQS_DP<0>")
	)
	(arc
		(start 338.640166 -279.971754)
		(mid 338.562537 -280.250167)
		(end 338.357464 -280.453846)
		(width 0.088646)
		(layer "In4.Cu")
		(net "M_C_CPU0_SA_DQS_DP<0>")
	)
	(arc
		(start 335.538064 -285.336996)
		(mid 335.255362 -285.412772)
		(end 334.97266 -285.336996)
		(width 0.088646)
		(layer "In4.Cu")
		(net "M_C_CPU0_SA_DQS_DP<0>")
	)
	(arc
		(start 338.348574 -278.83104)
		(mid 338.169977 -279.150318)
		(end 338.348574 -279.469596)
		(width 0.088646)
		(layer "In4.Cu")
		(net "M_C_CPU0_SA_DQS_DP<0>")
	)
	(arc
		(start 336.290666 -284.033722)
		(mid 336.218431 -284.310246)
		(end 336.020156 -284.516068)
		(width 0.088646)
		(layer "In4.Cu")
		(net "M_C_CPU0_SA_DQS_DP<0>")
	)
	(arc
		(start 337.89366 -281.919934)
		(mid 338.096247 -282.126285)
		(end 338.170266 -282.405836)
		(width 0.088646)
		(layer "In4.Cu")
		(net "M_C_CPU0_SA_DQS_DP<0>")
	)
	(arc
		(start 339.19033 -277.909782)
		(mid 339.001768 -277.935862)
		(end 338.827364 -278.012144)
		(width 0.088646)
		(layer "In4.Cu")
		(net "M_C_CPU0_SA_DQS_DP<0>")
	)
	(arc
		(start 336.760312 -283.2354)
		(mid 336.680942 -283.509134)
		(end 336.478118 -283.709364)
		(width 0.088646)
		(layer "In4.Cu")
		(net "M_C_CPU0_SA_DQS_DP<0>")
	)
	(arc
		(start 338.170012 -280.78811)
		(mid 338.091901 -281.065059)
		(end 337.887564 -281.267662)
		(width 0.088646)
		(layer "In4.Cu")
		(net "M_C_CPU0_SA_DQS_DP<0>")
	)
	(arc
		(start 338.639912 -278.346408)
		(mid 338.561801 -278.623357)
		(end 338.357464 -278.82596)
		(width 0.088646)
		(layer "In4.Cu")
		(net "M_C_CPU0_SA_DQS_DP<0>")
	)
	(segment
		(start 282.321508 -274.66671)
		(end 282.060396 -274.405598)
		(width 0.20066)
		(layer "F.Cu")
		(net "M_C_CPU0_SA_DQS_DN<9>")
	)
	(segment
		(start 276.474174 -274.405598)
		(end 276.000972 -274.405598)
		(width 0.20066)
		(layer "F.Cu")
		(net "M_C_CPU0_SA_DQS_DN<9>")
	)
	(segment
		(start 280.055066 -274.241768)
		(end 279.96515 -274.241768)
		(width 0.20066)
		(layer "F.Cu")
		(net "M_C_CPU0_SA_DQS_DN<9>")
	)
	(segment
		(start 275.73986 -274.66671)
		(end 275.268182 -274.66671)
		(width 0.20066)
		(layer "F.Cu")
		(net "M_C_CPU0_SA_DQS_DN<9>")
	)
	(segment
		(start 277.147782 -273.98599)
		(end 276.893782 -273.98599)
		(width 0.20066)
		(layer "F.Cu")
		(net "M_C_CPU0_SA_DQS_DN<9>")
	)
	(segment
		(start 277.40356 -274.241768)
		(end 277.147782 -273.98599)
		(width 0.20066)
		(layer "F.Cu")
		(net "M_C_CPU0_SA_DQS_DN<9>")
	)
	(segment
		(start 283.916882 -274.66671)
		(end 282.811982 -274.66671)
		(width 0.20066)
		(layer "F.Cu")
		(net "M_C_CPU0_SA_DQS_DN<9>")
	)
	(segment
		(start 279.912826 -274.241768)
		(end 277.83536 -274.241768)
		(width 0.1016)
		(layer "F.Cu")
		(net "M_C_CPU0_SA_DQS_DN<9>")
	)
	(segment
		(start 277.456392 -274.241768)
		(end 277.40356 -274.241768)
		(width 0.20066)
		(layer "F.Cu")
		(net "M_C_CPU0_SA_DQS_DN<9>")
	)
	(segment
		(start 280.7208 -273.980656)
		(end 280.316178 -273.980656)
		(width 0.20066)
		(layer "F.Cu")
		(net "M_C_CPU0_SA_DQS_DN<9>")
	)
	(segment
		(start 277.83536 -274.241768)
		(end 277.456392 -274.241768)
		(width 0.101854)
		(layer "F.Cu")
		(net "M_C_CPU0_SA_DQS_DN<9>")
	)
	(segment
		(start 345.593162 -259.894832)
		(end 345.593416 -260.430772)
		(width 0.20066)
		(layer "F.Cu")
		(net "M_C_CPU0_SA_DQS_DN<9>")
	)
	(segment
		(start 281.356816 -274.405598)
		(end 280.7208 -273.980656)
		(width 0.20066)
		(layer "F.Cu")
		(net "M_C_CPU0_SA_DQS_DN<9>")
	)
	(segment
		(start 279.96515 -274.241768)
		(end 279.912826 -274.241768)
		(width 0.101854)
		(layer "F.Cu")
		(net "M_C_CPU0_SA_DQS_DN<9>")
	)
	(segment
		(start 276.893782 -273.98599)
		(end 276.474174 -274.405598)
		(width 0.20066)
		(layer "F.Cu")
		(net "M_C_CPU0_SA_DQS_DN<9>")
	)
	(segment
		(start 276.000972 -274.405598)
		(end 275.73986 -274.66671)
		(width 0.20066)
		(layer "F.Cu")
		(net "M_C_CPU0_SA_DQS_DN<9>")
	)
	(segment
		(start 282.811982 -274.66671)
		(end 282.321508 -274.66671)
		(width 0.20066)
		(layer "F.Cu")
		(net "M_C_CPU0_SA_DQS_DN<9>")
	)
	(segment
		(start 282.060396 -274.405598)
		(end 281.356816 -274.405598)
		(width 0.20066)
		(layer "F.Cu")
		(net "M_C_CPU0_SA_DQS_DN<9>")
	)
	(segment
		(start 280.316178 -273.980656)
		(end 280.055066 -274.241768)
		(width 0.20066)
		(layer "F.Cu")
		(net "M_C_CPU0_SA_DQS_DN<9>")
	)
	(segment
		(start 286.685736 -273.346164)
		(end 285.444946 -274.586954)
		(width 0.18288)
		(layer "In6.Cu")
		(net "M_C_CPU0_SA_DQS_DN<9>")
	)
	(segment
		(start 330.68133 -261.837678)
		(end 330.621386 -261.897622)
		(width 0.088646)
		(layer "In6.Cu")
		(net "M_C_CPU0_SA_DQS_DN<9>")
	)
	(segment
		(start 295.171876 -270.842232)
		(end 294.715692 -270.842232)
		(width 0.18288)
		(layer "In6.Cu")
		(net "M_C_CPU0_SA_DQS_DN<9>")
	)
	(segment
		(start 295.458896 -270.555212)
		(end 295.171876 -270.842232)
		(width 0.18288)
		(layer "In6.Cu")
		(net "M_C_CPU0_SA_DQS_DN<9>")
	)
	(segment
		(start 284.635956 -274.389088)
		(end 284.194504 -274.389088)
		(width 0.18288)
		(layer "In6.Cu")
		(net "M_C_CPU0_SA_DQS_DN<9>")
	)
	(segment
		(start 290.982146 -270.878046)
		(end 289.80638 -272.053558)
		(width 0.18288)
		(layer "In6.Cu")
		(net "M_C_CPU0_SA_DQS_DN<9>")
	)
	(segment
		(start 294.715692 -270.842232)
		(end 294.430704 -270.557244)
		(width 0.18288)
		(layer "In6.Cu")
		(net "M_C_CPU0_SA_DQS_DN<9>")
	)
	(segment
		(start 310.29783 -266.536424)
		(end 309.853076 -266.536424)
		(width 0.18288)
		(layer "In6.Cu")
		(net "M_C_CPU0_SA_DQS_DN<9>")
	)
	(segment
		(start 297.30065 -268.57198)
		(end 296.800524 -268.77899)
		(width 0.18288)
		(layer "In6.Cu")
		(net "M_C_CPU0_SA_DQS_DN<9>")
	)
	(segment
		(start 293.185088 -269.96898)
		(end 292.247574 -269.96898)
		(width 0.18288)
		(layer "In6.Cu")
		(net "M_C_CPU0_SA_DQS_DN<9>")
	)
	(segment
		(start 285.444946 -274.586954)
		(end 284.833822 -274.586954)
		(width 0.18288)
		(layer "In6.Cu")
		(net "M_C_CPU0_SA_DQS_DN<9>")
	)
	(segment
		(start 304.36185 -267.274548)
		(end 302.578008 -268.012926)
		(width 0.18288)
		(layer "In6.Cu")
		(net "M_C_CPU0_SA_DQS_DN<9>")
	)
	(segment
		(start 299.26153 -268.302486)
		(end 298.826174 -268.302486)
		(width 0.18288)
		(layer "In6.Cu")
		(net "M_C_CPU0_SA_DQS_DN<9>")
	)
	(segment
		(start 296.800524 -268.77899)
		(end 296.278808 -269.300706)
		(width 0.18288)
		(layer "In6.Cu")
		(net "M_C_CPU0_SA_DQS_DN<9>")
	)
	(segment
		(start 329.416918 -261.897622)
		(end 326.276208 -263.198864)
		(width 0.18288)
		(layer "In6.Cu")
		(net "M_C_CPU0_SA_DQS_DN<9>")
	)
	(segment
		(start 296.278808 -270.150844)
		(end 295.87444 -270.555212)
		(width 0.18288)
		(layer "In6.Cu")
		(net "M_C_CPU0_SA_DQS_DN<9>")
	)
	(segment
		(start 330.621386 -261.897622)
		(end 330.598018 -261.897622)
		(width 0.088646)
		(layer "In6.Cu")
		(net "M_C_CPU0_SA_DQS_DN<9>")
	)
	(segment
		(start 338.357464 -260.920484)
		(end 338.342732 -260.92912)
		(width 0.088646)
		(layer "In6.Cu")
		(net "M_C_CPU0_SA_DQS_DN<9>")
	)
	(segment
		(start 295.87444 -270.555212)
		(end 295.458896 -270.555212)
		(width 0.18288)
		(layer "In6.Cu")
		(net "M_C_CPU0_SA_DQS_DN<9>")
	)
	(segment
		(start 342.505792 -260.92912)
		(end 342.49106 -260.920484)
		(width 0.088646)
		(layer "In6.Cu")
		(net "M_C_CPU0_SA_DQS_DN<9>")
	)
	(segment
		(start 326.276208 -263.198864)
		(end 319.793366 -263.198864)
		(width 0.18288)
		(layer "In6.Cu")
		(net "M_C_CPU0_SA_DQS_DN<9>")
	)
	(segment
		(start 293.773352 -270.557244)
		(end 293.185088 -269.96898)
		(width 0.18288)
		(layer "In6.Cu")
		(net "M_C_CPU0_SA_DQS_DN<9>")
	)
	(segment
		(start 339.297264 -260.920484)
		(end 339.282532 -260.92912)
		(width 0.088646)
		(layer "In6.Cu")
		(net "M_C_CPU0_SA_DQS_DN<9>")
	)
	(segment
		(start 307.61178 -267.771626)
		(end 306.41163 -267.274548)
		(width 0.18288)
		(layer "In6.Cu")
		(net "M_C_CPU0_SA_DQS_DN<9>")
	)
	(segment
		(start 284.833822 -274.586954)
		(end 284.635956 -274.389088)
		(width 0.18288)
		(layer "In6.Cu")
		(net "M_C_CPU0_SA_DQS_DN<9>")
	)
	(segment
		(start 297.865292 -268.007084)
		(end 297.30065 -268.57198)
		(width 0.18288)
		(layer "In6.Cu")
		(net "M_C_CPU0_SA_DQS_DN<9>")
	)
	(segment
		(start 344.385392 -260.92912)
		(end 344.37066 -260.920484)
		(width 0.088646)
		(layer "In6.Cu")
		(net "M_C_CPU0_SA_DQS_DN<9>")
	)
	(segment
		(start 319.793366 -263.198864)
		(end 313.276488 -265.89863)
		(width 0.18288)
		(layer "In6.Cu")
		(net "M_C_CPU0_SA_DQS_DN<9>")
	)
	(segment
		(start 311.317894 -266.958826)
		(end 310.29783 -266.536424)
		(width 0.18288)
		(layer "In6.Cu")
		(net "M_C_CPU0_SA_DQS_DN<9>")
	)
	(segment
		(start 284.194504 -274.389088)
		(end 283.916882 -274.66671)
		(width 0.18288)
		(layer "In6.Cu")
		(net "M_C_CPU0_SA_DQS_DN<9>")
	)
	(segment
		(start 330.598018 -261.897622)
		(end 329.416918 -261.897622)
		(width 0.18288)
		(layer "In6.Cu")
		(net "M_C_CPU0_SA_DQS_DN<9>")
	)
	(segment
		(start 345.280234 -260.430772)
		(end 345.214956 -260.49605)
		(width 0.088646)
		(layer "In6.Cu")
		(net "M_C_CPU0_SA_DQS_DN<9>")
	)
	(segment
		(start 296.278808 -269.300706)
		(end 296.278808 -270.150844)
		(width 0.18288)
		(layer "In6.Cu")
		(net "M_C_CPU0_SA_DQS_DN<9>")
	)
	(segment
		(start 298.826174 -268.302486)
		(end 298.530772 -268.007084)
		(width 0.18288)
		(layer "In6.Cu")
		(net "M_C_CPU0_SA_DQS_DN<9>")
	)
	(segment
		(start 298.530772 -268.007084)
		(end 297.865292 -268.007084)
		(width 0.18288)
		(layer "In6.Cu")
		(net "M_C_CPU0_SA_DQS_DN<9>")
	)
	(segment
		(start 302.578008 -268.012926)
		(end 299.55109 -268.012926)
		(width 0.18288)
		(layer "In6.Cu")
		(net "M_C_CPU0_SA_DQS_DN<9>")
	)
	(segment
		(start 291.59073 -270.625824)
		(end 290.982146 -270.878046)
		(width 0.18288)
		(layer "In6.Cu")
		(net "M_C_CPU0_SA_DQS_DN<9>")
	)
	(segment
		(start 342.116664 -260.920484)
		(end 342.101932 -260.92912)
		(width 0.088646)
		(layer "In6.Cu")
		(net "M_C_CPU0_SA_DQS_DN<9>")
	)
	(segment
		(start 309.853076 -266.536424)
		(end 309.392574 -266.727178)
		(width 0.18288)
		(layer "In6.Cu")
		(net "M_C_CPU0_SA_DQS_DN<9>")
	)
	(segment
		(start 331.879702 -260.995414)
		(end 331.037438 -261.837678)
		(width 0.088646)
		(layer "In6.Cu")
		(net "M_C_CPU0_SA_DQS_DN<9>")
	)
	(segment
		(start 337.417664 -260.920484)
		(end 337.402932 -260.92912)
		(width 0.088646)
		(layer "In6.Cu")
		(net "M_C_CPU0_SA_DQS_DN<9>")
	)
	(segment
		(start 309.392574 -266.727178)
		(end 308.348126 -267.771626)
		(width 0.18288)
		(layer "In6.Cu")
		(net "M_C_CPU0_SA_DQS_DN<9>")
	)
	(segment
		(start 331.037438 -261.837678)
		(end 330.68133 -261.837678)
		(width 0.088646)
		(layer "In6.Cu")
		(net "M_C_CPU0_SA_DQS_DN<9>")
	)
	(segment
		(start 312.216038 -266.958826)
		(end 311.317894 -266.958826)
		(width 0.18288)
		(layer "In6.Cu")
		(net "M_C_CPU0_SA_DQS_DN<9>")
	)
	(segment
		(start 313.276488 -265.89863)
		(end 312.216038 -266.958826)
		(width 0.18288)
		(layer "In6.Cu")
		(net "M_C_CPU0_SA_DQS_DN<9>")
	)
	(segment
		(start 292.247574 -269.96898)
		(end 291.59073 -270.625824)
		(width 0.18288)
		(layer "In6.Cu")
		(net "M_C_CPU0_SA_DQS_DN<9>")
	)
	(segment
		(start 294.430704 -270.557244)
		(end 293.773352 -270.557244)
		(width 0.18288)
		(layer "In6.Cu")
		(net "M_C_CPU0_SA_DQS_DN<9>")
	)
	(segment
		(start 308.348126 -267.771626)
		(end 307.61178 -267.771626)
		(width 0.18288)
		(layer "In6.Cu")
		(net "M_C_CPU0_SA_DQS_DN<9>")
	)
	(segment
		(start 341.176864 -260.920484)
		(end 341.162132 -260.92912)
		(width 0.088646)
		(layer "In6.Cu")
		(net "M_C_CPU0_SA_DQS_DN<9>")
	)
	(segment
		(start 299.55109 -268.012926)
		(end 299.26153 -268.302486)
		(width 0.18288)
		(layer "In6.Cu")
		(net "M_C_CPU0_SA_DQS_DN<9>")
	)
	(segment
		(start 343.996264 -260.920484)
		(end 343.981532 -260.92912)
		(width 0.088646)
		(layer "In6.Cu")
		(net "M_C_CPU0_SA_DQS_DN<9>")
	)
	(segment
		(start 345.593416 -260.430772)
		(end 345.280234 -260.430772)
		(width 0.088646)
		(layer "In6.Cu")
		(net "M_C_CPU0_SA_DQS_DN<9>")
	)
	(segment
		(start 306.41163 -267.274548)
		(end 304.36185 -267.274548)
		(width 0.18288)
		(layer "In6.Cu")
		(net "M_C_CPU0_SA_DQS_DN<9>")
	)
	(segment
		(start 289.80638 -272.053558)
		(end 286.685736 -273.346164)
		(width 0.18288)
		(layer "In6.Cu")
		(net "M_C_CPU0_SA_DQS_DN<9>")
	)
	(arc
		(start 345.214956 -260.49605)
		(mid 345.213658 -260.506604)
		(end 345.212162 -260.517132)
		(width 0.088646)
		(layer "In6.Cu")
		(net "M_C_CPU0_SA_DQS_DN<9>")
	)
	(arc
		(start 341.162132 -260.92912)
		(mid 340.885691 -260.996286)
		(end 340.61146 -260.920484)
		(width 0.088646)
		(layer "In6.Cu")
		(net "M_C_CPU0_SA_DQS_DN<9>")
	)
	(arc
		(start 339.282532 -260.92912)
		(mid 339.006091 -260.996286)
		(end 338.73186 -260.920484)
		(width 0.088646)
		(layer "In6.Cu")
		(net "M_C_CPU0_SA_DQS_DN<9>")
	)
	(arc
		(start 335.91246 -260.920484)
		(mid 335.725262 -260.870341)
		(end 335.538064 -260.920484)
		(width 0.088646)
		(layer "In6.Cu")
		(net "M_C_CPU0_SA_DQS_DN<9>")
	)
	(arc
		(start 342.101932 -260.92912)
		(mid 341.825491 -260.996286)
		(end 341.55126 -260.920484)
		(width 0.088646)
		(layer "In6.Cu")
		(net "M_C_CPU0_SA_DQS_DN<9>")
	)
	(arc
		(start 342.49106 -260.920484)
		(mid 342.303862 -260.870341)
		(end 342.116664 -260.920484)
		(width 0.088646)
		(layer "In6.Cu")
		(net "M_C_CPU0_SA_DQS_DN<9>")
	)
	(arc
		(start 334.598264 -260.920484)
		(mid 334.315562 -260.996226)
		(end 334.03286 -260.920484)
		(width 0.088646)
		(layer "In6.Cu")
		(net "M_C_CPU0_SA_DQS_DN<9>")
	)
	(arc
		(start 345.212162 -260.517132)
		(mid 345.119968 -260.750211)
		(end 344.936064 -260.920484)
		(width 0.088646)
		(layer "In6.Cu")
		(net "M_C_CPU0_SA_DQS_DN<9>")
	)
	(arc
		(start 340.61146 -260.920484)
		(mid 340.424262 -260.870341)
		(end 340.237064 -260.920484)
		(width 0.088646)
		(layer "In6.Cu")
		(net "M_C_CPU0_SA_DQS_DN<9>")
	)
	(arc
		(start 337.402932 -260.92912)
		(mid 337.126491 -260.996286)
		(end 336.85226 -260.920484)
		(width 0.088646)
		(layer "In6.Cu")
		(net "M_C_CPU0_SA_DQS_DN<9>")
	)
	(arc
		(start 343.056464 -260.920484)
		(mid 342.782235 -260.996409)
		(end 342.505792 -260.92912)
		(width 0.088646)
		(layer "In6.Cu")
		(net "M_C_CPU0_SA_DQS_DN<9>")
	)
	(arc
		(start 343.43086 -260.920484)
		(mid 343.243662 -260.870341)
		(end 343.056464 -260.920484)
		(width 0.088646)
		(layer "In6.Cu")
		(net "M_C_CPU0_SA_DQS_DN<9>")
	)
	(arc
		(start 336.477864 -260.920484)
		(mid 336.195162 -260.996226)
		(end 335.91246 -260.920484)
		(width 0.088646)
		(layer "In6.Cu")
		(net "M_C_CPU0_SA_DQS_DN<9>")
	)
	(arc
		(start 334.03286 -260.920484)
		(mid 333.845662 -260.870341)
		(end 333.658464 -260.920484)
		(width 0.088646)
		(layer "In6.Cu")
		(net "M_C_CPU0_SA_DQS_DN<9>")
	)
	(arc
		(start 337.79206 -260.920484)
		(mid 337.604862 -260.870341)
		(end 337.417664 -260.920484)
		(width 0.088646)
		(layer "In6.Cu")
		(net "M_C_CPU0_SA_DQS_DN<9>")
	)
	(arc
		(start 344.37066 -260.920484)
		(mid 344.183462 -260.870341)
		(end 343.996264 -260.920484)
		(width 0.088646)
		(layer "In6.Cu")
		(net "M_C_CPU0_SA_DQS_DN<9>")
	)
	(arc
		(start 332.718664 -260.920484)
		(mid 332.493466 -260.993396)
		(end 332.258162 -260.967728)
		(width 0.088646)
		(layer "In6.Cu")
		(net "M_C_CPU0_SA_DQS_DN<9>")
	)
	(arc
		(start 336.85226 -260.920484)
		(mid 336.665062 -260.870341)
		(end 336.477864 -260.920484)
		(width 0.088646)
		(layer "In6.Cu")
		(net "M_C_CPU0_SA_DQS_DN<9>")
	)
	(arc
		(start 339.67166 -260.920484)
		(mid 339.484462 -260.870341)
		(end 339.297264 -260.920484)
		(width 0.088646)
		(layer "In6.Cu")
		(net "M_C_CPU0_SA_DQS_DN<9>")
	)
	(arc
		(start 341.55126 -260.920484)
		(mid 341.364062 -260.870341)
		(end 341.176864 -260.920484)
		(width 0.088646)
		(layer "In6.Cu")
		(net "M_C_CPU0_SA_DQS_DN<9>")
	)
	(arc
		(start 334.97266 -260.920484)
		(mid 334.785462 -260.870341)
		(end 334.598264 -260.920484)
		(width 0.088646)
		(layer "In6.Cu")
		(net "M_C_CPU0_SA_DQS_DN<9>")
	)
	(arc
		(start 340.237064 -260.920484)
		(mid 339.954362 -260.996226)
		(end 339.67166 -260.920484)
		(width 0.088646)
		(layer "In6.Cu")
		(net "M_C_CPU0_SA_DQS_DN<9>")
	)
	(arc
		(start 335.538064 -260.920484)
		(mid 335.255362 -260.996226)
		(end 334.97266 -260.920484)
		(width 0.088646)
		(layer "In6.Cu")
		(net "M_C_CPU0_SA_DQS_DN<9>")
	)
	(arc
		(start 343.981532 -260.92912)
		(mid 343.705091 -260.996286)
		(end 343.43086 -260.920484)
		(width 0.088646)
		(layer "In6.Cu")
		(net "M_C_CPU0_SA_DQS_DN<9>")
	)
	(arc
		(start 332.258162 -260.967728)
		(mid 332.108825 -260.939693)
		(end 331.957426 -260.952488)
		(width 0.088646)
		(layer "In6.Cu")
		(net "M_C_CPU0_SA_DQS_DN<9>")
	)
	(arc
		(start 338.73186 -260.920484)
		(mid 338.544662 -260.870341)
		(end 338.357464 -260.920484)
		(width 0.088646)
		(layer "In6.Cu")
		(net "M_C_CPU0_SA_DQS_DN<9>")
	)
	(arc
		(start 333.658464 -260.920484)
		(mid 333.375762 -260.996226)
		(end 333.09306 -260.920484)
		(width 0.088646)
		(layer "In6.Cu")
		(net "M_C_CPU0_SA_DQS_DN<9>")
	)
	(arc
		(start 333.09306 -260.920484)
		(mid 332.905862 -260.870341)
		(end 332.718664 -260.920484)
		(width 0.088646)
		(layer "In6.Cu")
		(net "M_C_CPU0_SA_DQS_DN<9>")
	)
	(arc
		(start 344.936064 -260.920484)
		(mid 344.661835 -260.996409)
		(end 344.385392 -260.92912)
		(width 0.088646)
		(layer "In6.Cu")
		(net "M_C_CPU0_SA_DQS_DN<9>")
	)
	(arc
		(start 331.957426 -260.952488)
		(mid 331.915511 -260.968416)
		(end 331.879702 -260.995414)
		(width 0.088646)
		(layer "In6.Cu")
		(net "M_C_CPU0_SA_DQS_DN<9>")
	)
	(arc
		(start 338.342732 -260.92912)
		(mid 338.066291 -260.996286)
		(end 337.79206 -260.920484)
		(width 0.088646)
		(layer "In6.Cu")
		(net "M_C_CPU0_SA_DQS_DN<9>")
	)
	(segment
		(start 277.83536 -283.591762)
		(end 277.597362 -283.591762)
		(width 0.101854)
		(layer "F.Cu")
		(net "M_C_CPU0_SA_DQS_DN<8>")
	)
	(segment
		(start 280.7208 -283.33065)
		(end 280.316178 -283.33065)
		(width 0.20066)
		(layer "F.Cu")
		(net "M_C_CPU0_SA_DQS_DN<8>")
	)
	(segment
		(start 279.912826 -283.591762)
		(end 277.83536 -283.591762)
		(width 0.1016)
		(layer "F.Cu")
		(net "M_C_CPU0_SA_DQS_DN<8>")
	)
	(segment
		(start 282.321508 -284.016704)
		(end 282.060396 -283.755592)
		(width 0.20066)
		(layer "F.Cu")
		(net "M_C_CPU0_SA_DQS_DN<8>")
	)
	(segment
		(start 282.060396 -283.755592)
		(end 281.356816 -283.755592)
		(width 0.20066)
		(layer "F.Cu")
		(net "M_C_CPU0_SA_DQS_DN<8>")
	)
	(segment
		(start 276.474174 -283.755592)
		(end 276.000972 -283.755592)
		(width 0.20066)
		(layer "F.Cu")
		(net "M_C_CPU0_SA_DQS_DN<8>")
	)
	(segment
		(start 280.316178 -283.33065)
		(end 280.055066 -283.591762)
		(width 0.20066)
		(layer "F.Cu")
		(net "M_C_CPU0_SA_DQS_DN<8>")
	)
	(segment
		(start 277.597362 -283.591762)
		(end 277.58771 -283.601414)
		(width 0.101854)
		(layer "F.Cu")
		(net "M_C_CPU0_SA_DQS_DN<8>")
	)
	(segment
		(start 344.653362 -264.778236)
		(end 344.653616 -265.314176)
		(width 0.20066)
		(layer "F.Cu")
		(net "M_C_CPU0_SA_DQS_DN<8>")
	)
	(segment
		(start 277.58771 -283.601414)
		(end 277.404576 -283.601414)
		(width 0.20066)
		(layer "F.Cu")
		(net "M_C_CPU0_SA_DQS_DN<8>")
	)
	(segment
		(start 281.356816 -283.755592)
		(end 280.7208 -283.33065)
		(width 0.20066)
		(layer "F.Cu")
		(net "M_C_CPU0_SA_DQS_DN<8>")
	)
	(segment
		(start 277.404576 -283.601414)
		(end 277.136352 -283.33319)
		(width 0.20066)
		(layer "F.Cu")
		(net "M_C_CPU0_SA_DQS_DN<8>")
	)
	(segment
		(start 282.811982 -284.016704)
		(end 282.321508 -284.016704)
		(width 0.20066)
		(layer "F.Cu")
		(net "M_C_CPU0_SA_DQS_DN<8>")
	)
	(segment
		(start 276.896576 -283.33319)
		(end 276.474174 -283.755592)
		(width 0.20066)
		(layer "F.Cu")
		(net "M_C_CPU0_SA_DQS_DN<8>")
	)
	(segment
		(start 277.136352 -283.33319)
		(end 276.896576 -283.33319)
		(width 0.20066)
		(layer "F.Cu")
		(net "M_C_CPU0_SA_DQS_DN<8>")
	)
	(segment
		(start 283.916882 -284.016704)
		(end 282.811982 -284.016704)
		(width 0.20066)
		(layer "F.Cu")
		(net "M_C_CPU0_SA_DQS_DN<8>")
	)
	(segment
		(start 280.055066 -283.591762)
		(end 279.912826 -283.591762)
		(width 0.20066)
		(layer "F.Cu")
		(net "M_C_CPU0_SA_DQS_DN<8>")
	)
	(segment
		(start 276.000972 -283.755592)
		(end 275.73986 -284.016704)
		(width 0.20066)
		(layer "F.Cu")
		(net "M_C_CPU0_SA_DQS_DN<8>")
	)
	(segment
		(start 275.73986 -284.016704)
		(end 275.268182 -284.016704)
		(width 0.20066)
		(layer "F.Cu")
		(net "M_C_CPU0_SA_DQS_DN<8>")
	)
	(segment
		(start 297.881294 -279.063196)
		(end 297.032426 -279.912064)
		(width 0.18288)
		(layer "In6.Cu")
		(net "M_C_CPU0_SA_DQS_DN<8>")
	)
	(segment
		(start 303.93386 -276.493224)
		(end 302.876712 -277.550372)
		(width 0.18288)
		(layer "In6.Cu")
		(net "M_C_CPU0_SA_DQS_DN<8>")
	)
	(segment
		(start 298.527978 -279.063196)
		(end 297.881294 -279.063196)
		(width 0.18288)
		(layer "In6.Cu")
		(net "M_C_CPU0_SA_DQS_DN<8>")
	)
	(segment
		(start 295.184576 -280.191972)
		(end 294.706548 -280.191972)
		(width 0.18288)
		(layer "In6.Cu")
		(net "M_C_CPU0_SA_DQS_DN<8>")
	)
	(segment
		(start 289.42792 -283.306012)
		(end 288.32302 -283.306012)
		(width 0.18288)
		(layer "In6.Cu")
		(net "M_C_CPU0_SA_DQS_DN<8>")
	)
	(segment
		(start 327.066148 -268.401038)
		(end 326.484996 -268.401038)
		(width 0.18288)
		(layer "In6.Cu")
		(net "M_C_CPU0_SA_DQS_DN<8>")
	)
	(segment
		(start 304.88128 -276.493224)
		(end 303.93386 -276.493224)
		(width 0.18288)
		(layer "In6.Cu")
		(net "M_C_CPU0_SA_DQS_DN<8>")
	)
	(segment
		(start 302.097186 -277.550372)
		(end 300.562772 -279.084786)
		(width 0.18288)
		(layer "In6.Cu")
		(net "M_C_CPU0_SA_DQS_DN<8>")
	)
	(segment
		(start 294.706548 -280.191972)
		(end 294.415464 -279.900888)
		(width 0.18288)
		(layer "In6.Cu")
		(net "M_C_CPU0_SA_DQS_DN<8>")
	)
	(segment
		(start 344.96629 -265.314176)
		(end 345.023694 -265.256772)
		(width 0.088646)
		(layer "In6.Cu")
		(net "M_C_CPU0_SA_DQS_DN<8>")
	)
	(segment
		(start 284.5562 -283.737558)
		(end 284.196028 -283.737558)
		(width 0.18288)
		(layer "In6.Cu")
		(net "M_C_CPU0_SA_DQS_DN<8>")
	)
	(segment
		(start 294.415464 -279.900888)
		(end 293.639494 -279.900888)
		(width 0.18288)
		(layer "In6.Cu")
		(net "M_C_CPU0_SA_DQS_DN<8>")
	)
	(segment
		(start 342.975946 -264.998454)
		(end 342.961214 -264.989818)
		(width 0.088646)
		(layer "In6.Cu")
		(net "M_C_CPU0_SA_DQS_DN<8>")
	)
	(segment
		(start 297.032426 -279.912064)
		(end 295.464484 -279.912064)
		(width 0.18288)
		(layer "In6.Cu")
		(net "M_C_CPU0_SA_DQS_DN<8>")
	)
	(segment
		(start 306.667408 -276.493224)
		(end 305.67884 -276.493224)
		(width 0.18288)
		(layer "In6.Cu")
		(net "M_C_CPU0_SA_DQS_DN<8>")
	)
	(segment
		(start 308.704742 -275.988018)
		(end 308.580282 -275.863558)
		(width 0.18288)
		(layer "In6.Cu")
		(net "M_C_CPU0_SA_DQS_DN<8>")
	)
	(segment
		(start 340.151974 -264.995914)
		(end 340.14156 -264.989818)
		(width 0.088646)
		(layer "In6.Cu")
		(net "M_C_CPU0_SA_DQS_DN<8>")
	)
	(segment
		(start 330.09713 -267.14577)
		(end 327.066148 -268.401038)
		(width 0.18288)
		(layer "In6.Cu")
		(net "M_C_CPU0_SA_DQS_DN<8>")
	)
	(segment
		(start 292.03269 -281.507692)
		(end 291.22624 -281.507692)
		(width 0.18288)
		(layer "In6.Cu")
		(net "M_C_CPU0_SA_DQS_DN<8>")
	)
	(segment
		(start 313.70651 -274.762976)
		(end 312.18886 -276.280626)
		(width 0.18288)
		(layer "In6.Cu")
		(net "M_C_CPU0_SA_DQS_DN<8>")
	)
	(segment
		(start 284.196028 -283.737558)
		(end 283.916882 -284.016704)
		(width 0.18288)
		(layer "In6.Cu")
		(net "M_C_CPU0_SA_DQS_DN<8>")
	)
	(segment
		(start 330.979272 -267.14577)
		(end 330.09713 -267.14577)
		(width 0.18288)
		(layer "In6.Cu")
		(net "M_C_CPU0_SA_DQS_DN<8>")
	)
	(segment
		(start 331.062584 -267.085826)
		(end 331.00264 -267.14577)
		(width 0.088646)
		(layer "In6.Cu")
		(net "M_C_CPU0_SA_DQS_DN<8>")
	)
	(segment
		(start 333.001112 -265.314176)
		(end 333.001112 -265.324082)
		(width 0.088646)
		(layer "In6.Cu")
		(net "M_C_CPU0_SA_DQS_DN<8>")
	)
	(segment
		(start 293.639494 -279.900888)
		(end 292.03269 -281.507692)
		(width 0.18288)
		(layer "In6.Cu")
		(net "M_C_CPU0_SA_DQS_DN<8>")
	)
	(segment
		(start 339.767164 -264.989818)
		(end 339.75675 -264.995914)
		(width 0.088646)
		(layer "In6.Cu")
		(net "M_C_CPU0_SA_DQS_DN<8>")
	)
	(segment
		(start 326.484996 -268.401038)
		(end 318.891412 -271.547082)
		(width 0.18288)
		(layer "In6.Cu")
		(net "M_C_CPU0_SA_DQS_DN<8>")
	)
	(segment
		(start 305.00574 -276.617684)
		(end 304.88128 -276.493224)
		(width 0.18288)
		(layer "In6.Cu")
		(net "M_C_CPU0_SA_DQS_DN<8>")
	)
	(segment
		(start 341.096346 -264.998454)
		(end 341.081614 -264.989818)
		(width 0.088646)
		(layer "In6.Cu")
		(net "M_C_CPU0_SA_DQS_DN<8>")
	)
	(segment
		(start 302.876712 -277.550372)
		(end 302.097186 -277.550372)
		(width 0.18288)
		(layer "In6.Cu")
		(net "M_C_CPU0_SA_DQS_DN<8>")
	)
	(segment
		(start 312.18886 -276.280626)
		(end 311.230518 -276.280626)
		(width 0.18288)
		(layer "In6.Cu")
		(net "M_C_CPU0_SA_DQS_DN<8>")
	)
	(segment
		(start 309.253382 -275.988018)
		(end 308.704742 -275.988018)
		(width 0.18288)
		(layer "In6.Cu")
		(net "M_C_CPU0_SA_DQS_DN<8>")
	)
	(segment
		(start 344.653616 -265.314176)
		(end 344.96629 -265.314176)
		(width 0.088646)
		(layer "In6.Cu")
		(net "M_C_CPU0_SA_DQS_DN<8>")
	)
	(segment
		(start 284.73654 -283.917898)
		(end 284.5562 -283.737558)
		(width 0.18288)
		(layer "In6.Cu")
		(net "M_C_CPU0_SA_DQS_DN<8>")
	)
	(segment
		(start 299.284644 -279.341834)
		(end 298.806616 -279.341834)
		(width 0.18288)
		(layer "In6.Cu")
		(net "M_C_CPU0_SA_DQS_DN<8>")
	)
	(segment
		(start 307.297074 -275.863558)
		(end 306.667408 -276.493224)
		(width 0.18288)
		(layer "In6.Cu")
		(net "M_C_CPU0_SA_DQS_DN<8>")
	)
	(segment
		(start 295.464484 -279.912064)
		(end 295.184576 -280.191972)
		(width 0.18288)
		(layer "In6.Cu")
		(net "M_C_CPU0_SA_DQS_DN<8>")
	)
	(segment
		(start 311.230518 -276.280626)
		(end 310.81345 -275.863558)
		(width 0.18288)
		(layer "In6.Cu")
		(net "M_C_CPU0_SA_DQS_DN<8>")
	)
	(segment
		(start 331.41793 -267.085826)
		(end 331.062584 -267.085826)
		(width 0.088646)
		(layer "In6.Cu")
		(net "M_C_CPU0_SA_DQS_DN<8>")
	)
	(segment
		(start 300.562772 -279.084786)
		(end 299.541692 -279.084786)
		(width 0.18288)
		(layer "In6.Cu")
		(net "M_C_CPU0_SA_DQS_DN<8>")
	)
	(segment
		(start 338.272374 -264.995914)
		(end 338.26196 -264.989818)
		(width 0.088646)
		(layer "In6.Cu")
		(net "M_C_CPU0_SA_DQS_DN<8>")
	)
	(segment
		(start 305.55438 -276.617684)
		(end 305.00574 -276.617684)
		(width 0.18288)
		(layer "In6.Cu")
		(net "M_C_CPU0_SA_DQS_DN<8>")
	)
	(segment
		(start 332.640686 -265.86307)
		(end 331.41793 -267.085826)
		(width 0.088646)
		(layer "In6.Cu")
		(net "M_C_CPU0_SA_DQS_DN<8>")
	)
	(segment
		(start 318.891412 -271.547082)
		(end 315.675518 -274.762976)
		(width 0.18288)
		(layer "In6.Cu")
		(net "M_C_CPU0_SA_DQS_DN<8>")
	)
	(segment
		(start 331.00264 -267.14577)
		(end 330.979272 -267.14577)
		(width 0.088646)
		(layer "In6.Cu")
		(net "M_C_CPU0_SA_DQS_DN<8>")
	)
	(segment
		(start 298.806616 -279.341834)
		(end 298.527978 -279.063196)
		(width 0.18288)
		(layer "In6.Cu")
		(net "M_C_CPU0_SA_DQS_DN<8>")
	)
	(segment
		(start 287.711134 -283.917898)
		(end 284.73654 -283.917898)
		(width 0.18288)
		(layer "In6.Cu")
		(net "M_C_CPU0_SA_DQS_DN<8>")
	)
	(segment
		(start 342.036146 -264.998454)
		(end 342.021414 -264.989818)
		(width 0.088646)
		(layer "In6.Cu")
		(net "M_C_CPU0_SA_DQS_DN<8>")
	)
	(segment
		(start 315.675518 -274.762976)
		(end 313.70651 -274.762976)
		(width 0.18288)
		(layer "In6.Cu")
		(net "M_C_CPU0_SA_DQS_DN<8>")
	)
	(segment
		(start 299.541692 -279.084786)
		(end 299.284644 -279.341834)
		(width 0.18288)
		(layer "In6.Cu")
		(net "M_C_CPU0_SA_DQS_DN<8>")
	)
	(segment
		(start 305.67884 -276.493224)
		(end 305.55438 -276.617684)
		(width 0.18288)
		(layer "In6.Cu")
		(net "M_C_CPU0_SA_DQS_DN<8>")
	)
	(segment
		(start 309.377842 -275.863558)
		(end 309.253382 -275.988018)
		(width 0.18288)
		(layer "In6.Cu")
		(net "M_C_CPU0_SA_DQS_DN<8>")
	)
	(segment
		(start 310.81345 -275.863558)
		(end 309.377842 -275.863558)
		(width 0.18288)
		(layer "In6.Cu")
		(net "M_C_CPU0_SA_DQS_DN<8>")
	)
	(segment
		(start 343.915746 -264.998454)
		(end 343.901014 -264.989818)
		(width 0.088646)
		(layer "In6.Cu")
		(net "M_C_CPU0_SA_DQS_DN<8>")
	)
	(segment
		(start 308.580282 -275.863558)
		(end 307.297074 -275.863558)
		(width 0.18288)
		(layer "In6.Cu")
		(net "M_C_CPU0_SA_DQS_DN<8>")
	)
	(segment
		(start 291.22624 -281.507692)
		(end 289.42792 -283.306012)
		(width 0.18288)
		(layer "In6.Cu")
		(net "M_C_CPU0_SA_DQS_DN<8>")
	)
	(segment
		(start 288.32302 -283.306012)
		(end 287.711134 -283.917898)
		(width 0.18288)
		(layer "In6.Cu")
		(net "M_C_CPU0_SA_DQS_DN<8>")
	)
	(arc
		(start 333.001112 -265.324082)
		(mid 332.923001 -265.601031)
		(end 332.718664 -265.803634)
		(width 0.088646)
		(layer "In6.Cu")
		(net "M_C_CPU0_SA_DQS_DN<8>")
	)
	(arc
		(start 337.887564 -264.989818)
		(mid 337.604862 -265.065594)
		(end 337.32216 -264.989818)
		(width 0.088646)
		(layer "In6.Cu")
		(net "M_C_CPU0_SA_DQS_DN<8>")
	)
	(arc
		(start 336.947764 -264.989818)
		(mid 336.665062 -265.065594)
		(end 336.38236 -264.989818)
		(width 0.088646)
		(layer "In6.Cu")
		(net "M_C_CPU0_SA_DQS_DN<8>")
	)
	(arc
		(start 338.827618 -264.989818)
		(mid 338.550805 -265.065688)
		(end 338.272374 -264.995914)
		(width 0.088646)
		(layer "In6.Cu")
		(net "M_C_CPU0_SA_DQS_DN<8>")
	)
	(arc
		(start 333.56296 -264.989818)
		(mid 333.188485 -264.989864)
		(end 333.001112 -265.314176)
		(width 0.088646)
		(layer "In6.Cu")
		(net "M_C_CPU0_SA_DQS_DN<8>")
	)
	(arc
		(start 338.26196 -264.989818)
		(mid 338.074762 -264.939675)
		(end 337.887564 -264.989818)
		(width 0.088646)
		(layer "In6.Cu")
		(net "M_C_CPU0_SA_DQS_DN<8>")
	)
	(arc
		(start 335.44256 -264.989818)
		(mid 335.255362 -264.939675)
		(end 335.068164 -264.989818)
		(width 0.088646)
		(layer "In6.Cu")
		(net "M_C_CPU0_SA_DQS_DN<8>")
	)
	(arc
		(start 340.14156 -264.989818)
		(mid 339.954362 -264.939675)
		(end 339.767164 -264.989818)
		(width 0.088646)
		(layer "In6.Cu")
		(net "M_C_CPU0_SA_DQS_DN<8>")
	)
	(arc
		(start 340.707218 -264.989818)
		(mid 340.430405 -265.065688)
		(end 340.151974 -264.995914)
		(width 0.088646)
		(layer "In6.Cu")
		(net "M_C_CPU0_SA_DQS_DN<8>")
	)
	(arc
		(start 344.466418 -264.989818)
		(mid 344.192219 -265.065653)
		(end 343.915746 -264.998454)
		(width 0.088646)
		(layer "In6.Cu")
		(net "M_C_CPU0_SA_DQS_DN<8>")
	)
	(arc
		(start 339.75675 -264.995914)
		(mid 339.478572 -265.065637)
		(end 339.202014 -264.989818)
		(width 0.088646)
		(layer "In6.Cu")
		(net "M_C_CPU0_SA_DQS_DN<8>")
	)
	(arc
		(start 335.068164 -264.989818)
		(mid 334.785462 -265.065594)
		(end 334.50276 -264.989818)
		(width 0.088646)
		(layer "In6.Cu")
		(net "M_C_CPU0_SA_DQS_DN<8>")
	)
	(arc
		(start 341.081614 -264.989818)
		(mid 340.894416 -264.939675)
		(end 340.707218 -264.989818)
		(width 0.088646)
		(layer "In6.Cu")
		(net "M_C_CPU0_SA_DQS_DN<8>")
	)
	(arc
		(start 343.901014 -264.989818)
		(mid 343.713816 -264.939675)
		(end 343.526618 -264.989818)
		(width 0.088646)
		(layer "In6.Cu")
		(net "M_C_CPU0_SA_DQS_DN<8>")
	)
	(arc
		(start 342.586818 -264.989818)
		(mid 342.312619 -265.065653)
		(end 342.036146 -264.998454)
		(width 0.088646)
		(layer "In6.Cu")
		(net "M_C_CPU0_SA_DQS_DN<8>")
	)
	(arc
		(start 343.526618 -264.989818)
		(mid 343.252419 -265.065653)
		(end 342.975946 -264.998454)
		(width 0.088646)
		(layer "In6.Cu")
		(net "M_C_CPU0_SA_DQS_DN<8>")
	)
	(arc
		(start 342.961214 -264.989818)
		(mid 342.774016 -264.939675)
		(end 342.586818 -264.989818)
		(width 0.088646)
		(layer "In6.Cu")
		(net "M_C_CPU0_SA_DQS_DN<8>")
	)
	(arc
		(start 339.202014 -264.989818)
		(mid 339.014816 -264.939675)
		(end 338.827618 -264.989818)
		(width 0.088646)
		(layer "In6.Cu")
		(net "M_C_CPU0_SA_DQS_DN<8>")
	)
	(arc
		(start 332.718664 -265.803634)
		(mid 332.677711 -265.830777)
		(end 332.640686 -265.86307)
		(width 0.088646)
		(layer "In6.Cu")
		(net "M_C_CPU0_SA_DQS_DN<8>")
	)
	(arc
		(start 337.32216 -264.989818)
		(mid 337.134962 -264.939675)
		(end 336.947764 -264.989818)
		(width 0.088646)
		(layer "In6.Cu")
		(net "M_C_CPU0_SA_DQS_DN<8>")
	)
	(arc
		(start 341.647018 -264.989818)
		(mid 341.372819 -265.065653)
		(end 341.096346 -264.998454)
		(width 0.088646)
		(layer "In6.Cu")
		(net "M_C_CPU0_SA_DQS_DN<8>")
	)
	(arc
		(start 342.021414 -264.989818)
		(mid 341.834216 -264.939675)
		(end 341.647018 -264.989818)
		(width 0.088646)
		(layer "In6.Cu")
		(net "M_C_CPU0_SA_DQS_DN<8>")
	)
	(arc
		(start 334.50276 -264.989818)
		(mid 334.315562 -264.939675)
		(end 334.128364 -264.989818)
		(width 0.088646)
		(layer "In6.Cu")
		(net "M_C_CPU0_SA_DQS_DN<8>")
	)
	(arc
		(start 334.128364 -264.989818)
		(mid 333.845662 -265.065594)
		(end 333.56296 -264.989818)
		(width 0.088646)
		(layer "In6.Cu")
		(net "M_C_CPU0_SA_DQS_DN<8>")
	)
	(arc
		(start 336.38236 -264.989818)
		(mid 336.195162 -264.939675)
		(end 336.007964 -264.989818)
		(width 0.088646)
		(layer "In6.Cu")
		(net "M_C_CPU0_SA_DQS_DN<8>")
	)
	(arc
		(start 345.023694 -265.256772)
		(mid 344.81545 -264.976233)
		(end 344.466418 -264.989818)
		(width 0.088646)
		(layer "In6.Cu")
		(net "M_C_CPU0_SA_DQS_DN<8>")
	)
	(arc
		(start 336.007964 -264.989818)
		(mid 335.725262 -265.065594)
		(end 335.44256 -264.989818)
		(width 0.088646)
		(layer "In6.Cu")
		(net "M_C_CPU0_SA_DQS_DN<8>")
	)
	(segment
		(start 276.000972 -293.105586)
		(end 275.73986 -293.366698)
		(width 0.20066)
		(layer "F.Cu")
		(net "M_C_CPU0_SA_DQS_DN<7>")
	)
	(segment
		(start 277.404576 -292.951408)
		(end 277.136352 -292.683184)
		(width 0.20066)
		(layer "F.Cu")
		(net "M_C_CPU0_SA_DQS_DN<7>")
	)
	(segment
		(start 277.589234 -292.951408)
		(end 277.58771 -292.951408)
		(width 0.101854)
		(layer "F.Cu")
		(net "M_C_CPU0_SA_DQS_DN<7>")
	)
	(segment
		(start 277.598886 -292.941756)
		(end 277.589234 -292.951408)
		(width 0.101854)
		(layer "F.Cu")
		(net "M_C_CPU0_SA_DQS_DN<7>")
	)
	(segment
		(start 342.304116 -267.219938)
		(end 342.303862 -267.755878)
		(width 0.20066)
		(layer "F.Cu")
		(net "M_C_CPU0_SA_DQS_DN<7>")
	)
	(segment
		(start 282.321508 -293.366698)
		(end 282.060396 -293.105586)
		(width 0.20066)
		(layer "F.Cu")
		(net "M_C_CPU0_SA_DQS_DN<7>")
	)
	(segment
		(start 279.912826 -292.941756)
		(end 277.83536 -292.941756)
		(width 0.1016)
		(layer "F.Cu")
		(net "M_C_CPU0_SA_DQS_DN<7>")
	)
	(segment
		(start 282.811982 -293.366698)
		(end 282.321508 -293.366698)
		(width 0.20066)
		(layer "F.Cu")
		(net "M_C_CPU0_SA_DQS_DN<7>")
	)
	(segment
		(start 277.58771 -292.951408)
		(end 277.404576 -292.951408)
		(width 0.20066)
		(layer "F.Cu")
		(net "M_C_CPU0_SA_DQS_DN<7>")
	)
	(segment
		(start 280.7208 -292.680644)
		(end 280.316178 -292.680644)
		(width 0.20066)
		(layer "F.Cu")
		(net "M_C_CPU0_SA_DQS_DN<7>")
	)
	(segment
		(start 275.73986 -293.366698)
		(end 275.268182 -293.366698)
		(width 0.20066)
		(layer "F.Cu")
		(net "M_C_CPU0_SA_DQS_DN<7>")
	)
	(segment
		(start 276.896576 -292.683184)
		(end 276.474174 -293.105586)
		(width 0.20066)
		(layer "F.Cu")
		(net "M_C_CPU0_SA_DQS_DN<7>")
	)
	(segment
		(start 281.356816 -293.105586)
		(end 280.7208 -292.680644)
		(width 0.20066)
		(layer "F.Cu")
		(net "M_C_CPU0_SA_DQS_DN<7>")
	)
	(segment
		(start 282.060396 -293.105586)
		(end 281.356816 -293.105586)
		(width 0.20066)
		(layer "F.Cu")
		(net "M_C_CPU0_SA_DQS_DN<7>")
	)
	(segment
		(start 276.474174 -293.105586)
		(end 276.000972 -293.105586)
		(width 0.20066)
		(layer "F.Cu")
		(net "M_C_CPU0_SA_DQS_DN<7>")
	)
	(segment
		(start 280.055066 -292.941756)
		(end 279.912826 -292.941756)
		(width 0.20066)
		(layer "F.Cu")
		(net "M_C_CPU0_SA_DQS_DN<7>")
	)
	(segment
		(start 280.316178 -292.680644)
		(end 280.055066 -292.941756)
		(width 0.20066)
		(layer "F.Cu")
		(net "M_C_CPU0_SA_DQS_DN<7>")
	)
	(segment
		(start 277.83536 -292.941756)
		(end 277.598886 -292.941756)
		(width 0.101854)
		(layer "F.Cu")
		(net "M_C_CPU0_SA_DQS_DN<7>")
	)
	(segment
		(start 277.136352 -292.683184)
		(end 276.896576 -292.683184)
		(width 0.20066)
		(layer "F.Cu")
		(net "M_C_CPU0_SA_DQS_DN<7>")
	)
	(segment
		(start 283.916882 -293.366698)
		(end 282.811982 -293.366698)
		(width 0.20066)
		(layer "F.Cu")
		(net "M_C_CPU0_SA_DQS_DN<7>")
	)
	(segment
		(start 314.535058 -286.743394)
		(end 314.271152 -287.0073)
		(width 0.18288)
		(layer "In4.Cu")
		(net "M_C_CPU0_SA_DQS_DN<7>")
	)
	(segment
		(start 294.435276 -292.666674)
		(end 293.642288 -292.666674)
		(width 0.18288)
		(layer "In4.Cu")
		(net "M_C_CPU0_SA_DQS_DN<7>")
	)
	(segment
		(start 284.577282 -293.10076)
		(end 284.18282 -293.10076)
		(width 0.18288)
		(layer "In4.Cu")
		(net "M_C_CPU0_SA_DQS_DN<7>")
	)
	(segment
		(start 284.837632 -293.36111)
		(end 284.577282 -293.10076)
		(width 0.18288)
		(layer "In4.Cu")
		(net "M_C_CPU0_SA_DQS_DN<7>")
	)
	(segment
		(start 313.622436 -287.250886)
		(end 312.231786 -287.826958)
		(width 0.18288)
		(layer "In4.Cu")
		(net "M_C_CPU0_SA_DQS_DN<7>")
	)
	(segment
		(start 291.823394 -292.57117)
		(end 289.306254 -292.57117)
		(width 0.18288)
		(layer "In4.Cu")
		(net "M_C_CPU0_SA_DQS_DN<7>")
	)
	(segment
		(start 289.306254 -292.57117)
		(end 287.400238 -293.36111)
		(width 0.18288)
		(layer "In4.Cu")
		(net "M_C_CPU0_SA_DQS_DN<7>")
	)
	(segment
		(start 339.67928 -267.435584)
		(end 339.671914 -267.431266)
		(width 0.088646)
		(layer "In4.Cu")
		(net "M_C_CPU0_SA_DQS_DN<7>")
	)
	(segment
		(start 293.05504 -292.079426)
		(end 292.315138 -292.079426)
		(width 0.18288)
		(layer "In4.Cu")
		(net "M_C_CPU0_SA_DQS_DN<7>")
	)
	(segment
		(start 311.705752 -287.826958)
		(end 310.845454 -288.687256)
		(width 0.18288)
		(layer "In4.Cu")
		(net "M_C_CPU0_SA_DQS_DN<7>")
	)
	(segment
		(start 314.535058 -286.357314)
		(end 314.535058 -286.743394)
		(width 0.18288)
		(layer "In4.Cu")
		(net "M_C_CPU0_SA_DQS_DN<7>")
	)
	(segment
		(start 338.73948 -267.435584)
		(end 338.732114 -267.431266)
		(width 0.088646)
		(layer "In4.Cu")
		(net "M_C_CPU0_SA_DQS_DN<7>")
	)
	(segment
		(start 331.45984 -268.81582)
		(end 331.436472 -268.81582)
		(width 0.088646)
		(layer "In4.Cu")
		(net "M_C_CPU0_SA_DQS_DN<7>")
	)
	(segment
		(start 299.451014 -291.823394)
		(end 299.182536 -292.091872)
		(width 0.18288)
		(layer "In4.Cu")
		(net "M_C_CPU0_SA_DQS_DN<7>")
	)
	(segment
		(start 312.231786 -287.826958)
		(end 311.705752 -287.826958)
		(width 0.18288)
		(layer "In4.Cu")
		(net "M_C_CPU0_SA_DQS_DN<7>")
	)
	(segment
		(start 336.857086 -267.43406)
		(end 336.85226 -267.43152)
		(width 0.088646)
		(layer "In4.Cu")
		(net "M_C_CPU0_SA_DQS_DN<7>")
	)
	(segment
		(start 284.18282 -293.10076)
		(end 283.916882 -293.366698)
		(width 0.18288)
		(layer "In4.Cu")
		(net "M_C_CPU0_SA_DQS_DN<7>")
	)
	(segment
		(start 295.100756 -292.94201)
		(end 294.710612 -292.94201)
		(width 0.18288)
		(layer "In4.Cu")
		(net "M_C_CPU0_SA_DQS_DN<7>")
	)
	(segment
		(start 331.925676 -268.555978)
		(end 331.725778 -268.755876)
		(width 0.088646)
		(layer "In4.Cu")
		(net "M_C_CPU0_SA_DQS_DN<7>")
	)
	(segment
		(start 341.176864 -268.080236)
		(end 341.162132 -268.0716)
		(width 0.088646)
		(layer "In4.Cu")
		(net "M_C_CPU0_SA_DQS_DN<7>")
	)
	(segment
		(start 332.905354 -267.381228)
		(end 332.600554 -267.381228)
		(width 0.088646)
		(layer "In4.Cu")
		(net "M_C_CPU0_SA_DQS_DN<7>")
	)
	(segment
		(start 297.160696 -292.676072)
		(end 295.366694 -292.676072)
		(width 0.18288)
		(layer "In4.Cu")
		(net "M_C_CPU0_SA_DQS_DN<7>")
	)
	(segment
		(start 318.958214 -279.792684)
		(end 317.320168 -283.748988)
		(width 0.18288)
		(layer "In4.Cu")
		(net "M_C_CPU0_SA_DQS_DN<7>")
	)
	(segment
		(start 300.368716 -291.823394)
		(end 299.451014 -291.823394)
		(width 0.18288)
		(layer "In4.Cu")
		(net "M_C_CPU0_SA_DQS_DN<7>")
	)
	(segment
		(start 337.797902 -267.434568)
		(end 337.792314 -267.431266)
		(width 0.088646)
		(layer "In4.Cu")
		(net "M_C_CPU0_SA_DQS_DN<7>")
	)
	(segment
		(start 303.737264 -292.415722)
		(end 302.915574 -292.075362)
		(width 0.18288)
		(layer "In4.Cu")
		(net "M_C_CPU0_SA_DQS_DN<7>")
	)
	(segment
		(start 302.915574 -292.075362)
		(end 300.9773 -292.075362)
		(width 0.18288)
		(layer "In4.Cu")
		(net "M_C_CPU0_SA_DQS_DN<7>")
	)
	(segment
		(start 317.320168 -283.748988)
		(end 315.04636 -286.022796)
		(width 0.18288)
		(layer "In4.Cu")
		(net "M_C_CPU0_SA_DQS_DN<7>")
	)
	(segment
		(start 299.182536 -292.091872)
		(end 298.81068 -292.091872)
		(width 0.18288)
		(layer "In4.Cu")
		(net "M_C_CPU0_SA_DQS_DN<7>")
	)
	(segment
		(start 293.642288 -292.666674)
		(end 293.05504 -292.079426)
		(width 0.18288)
		(layer "In4.Cu")
		(net "M_C_CPU0_SA_DQS_DN<7>")
	)
	(segment
		(start 310.845454 -288.687256)
		(end 309.264812 -288.687256)
		(width 0.18288)
		(layer "In4.Cu")
		(net "M_C_CPU0_SA_DQS_DN<7>")
	)
	(segment
		(start 340.720426 -267.49502)
		(end 340.611714 -267.431266)
		(width 0.088646)
		(layer "In4.Cu")
		(net "M_C_CPU0_SA_DQS_DN<7>")
	)
	(segment
		(start 329.935078 -268.81582)
		(end 318.958214 -279.792684)
		(width 0.18288)
		(layer "In4.Cu")
		(net "M_C_CPU0_SA_DQS_DN<7>")
	)
	(segment
		(start 331.725778 -268.755876)
		(end 331.519784 -268.755876)
		(width 0.088646)
		(layer "In4.Cu")
		(net "M_C_CPU0_SA_DQS_DN<7>")
	)
	(segment
		(start 298.02201 -291.814758)
		(end 297.160696 -292.676072)
		(width 0.18288)
		(layer "In4.Cu")
		(net "M_C_CPU0_SA_DQS_DN<7>")
	)
	(segment
		(start 314.744862 -286.14751)
		(end 314.535058 -286.357314)
		(width 0.18288)
		(layer "In4.Cu")
		(net "M_C_CPU0_SA_DQS_DN<7>")
	)
	(segment
		(start 332.600554 -267.381228)
		(end 331.925676 -268.056106)
		(width 0.088646)
		(layer "In4.Cu")
		(net "M_C_CPU0_SA_DQS_DN<7>")
	)
	(segment
		(start 331.925676 -268.056106)
		(end 331.925676 -268.555978)
		(width 0.088646)
		(layer "In4.Cu")
		(net "M_C_CPU0_SA_DQS_DN<7>")
	)
	(segment
		(start 315.04636 -286.022796)
		(end 314.744862 -286.14751)
		(width 0.18288)
		(layer "In4.Cu")
		(net "M_C_CPU0_SA_DQS_DN<7>")
	)
	(segment
		(start 292.315138 -292.079426)
		(end 291.823394 -292.57117)
		(width 0.18288)
		(layer "In4.Cu")
		(net "M_C_CPU0_SA_DQS_DN<7>")
	)
	(segment
		(start 304.233834 -292.415722)
		(end 303.737264 -292.415722)
		(width 0.18288)
		(layer "In4.Cu")
		(net "M_C_CPU0_SA_DQS_DN<7>")
	)
	(segment
		(start 339.671914 -267.431266)
		(end 339.667342 -267.428726)
		(width 0.088646)
		(layer "In4.Cu")
		(net "M_C_CPU0_SA_DQS_DN<7>")
	)
	(segment
		(start 306.779676 -291.172392)
		(end 305.220624 -292.006528)
		(width 0.18288)
		(layer "In4.Cu")
		(net "M_C_CPU0_SA_DQS_DN<7>")
	)
	(segment
		(start 295.366694 -292.676072)
		(end 295.100756 -292.94201)
		(width 0.18288)
		(layer "In4.Cu")
		(net "M_C_CPU0_SA_DQS_DN<7>")
	)
	(segment
		(start 331.519784 -268.755876)
		(end 331.45984 -268.81582)
		(width 0.088646)
		(layer "In4.Cu")
		(net "M_C_CPU0_SA_DQS_DN<7>")
	)
	(segment
		(start 314.271152 -287.0073)
		(end 313.866022 -287.0073)
		(width 0.18288)
		(layer "In4.Cu")
		(net "M_C_CPU0_SA_DQS_DN<7>")
	)
	(segment
		(start 294.710612 -292.94201)
		(end 294.435276 -292.666674)
		(width 0.18288)
		(layer "In4.Cu")
		(net "M_C_CPU0_SA_DQS_DN<7>")
	)
	(segment
		(start 338.732114 -267.431266)
		(end 338.727542 -267.428726)
		(width 0.088646)
		(layer "In4.Cu")
		(net "M_C_CPU0_SA_DQS_DN<7>")
	)
	(segment
		(start 340.611714 -267.431266)
		(end 340.607142 -267.428726)
		(width 0.088646)
		(layer "In4.Cu")
		(net "M_C_CPU0_SA_DQS_DN<7>")
	)
	(segment
		(start 309.264812 -288.687256)
		(end 306.779676 -291.172392)
		(width 0.18288)
		(layer "In4.Cu")
		(net "M_C_CPU0_SA_DQS_DN<7>")
	)
	(segment
		(start 298.533566 -291.814758)
		(end 298.02201 -291.814758)
		(width 0.18288)
		(layer "In4.Cu")
		(net "M_C_CPU0_SA_DQS_DN<7>")
	)
	(segment
		(start 300.9773 -292.075362)
		(end 300.368716 -291.823394)
		(width 0.18288)
		(layer "In4.Cu")
		(net "M_C_CPU0_SA_DQS_DN<7>")
	)
	(segment
		(start 298.81068 -292.091872)
		(end 298.533566 -291.814758)
		(width 0.18288)
		(layer "In4.Cu")
		(net "M_C_CPU0_SA_DQS_DN<7>")
	)
	(segment
		(start 305.220624 -292.006528)
		(end 304.233834 -292.415722)
		(width 0.18288)
		(layer "In4.Cu")
		(net "M_C_CPU0_SA_DQS_DN<7>")
	)
	(segment
		(start 331.436472 -268.81582)
		(end 329.935078 -268.81582)
		(width 0.18288)
		(layer "In4.Cu")
		(net "M_C_CPU0_SA_DQS_DN<7>")
	)
	(segment
		(start 313.866022 -287.0073)
		(end 313.622436 -287.250886)
		(width 0.18288)
		(layer "In4.Cu")
		(net "M_C_CPU0_SA_DQS_DN<7>")
	)
	(segment
		(start 287.400238 -293.36111)
		(end 284.837632 -293.36111)
		(width 0.18288)
		(layer "In4.Cu")
		(net "M_C_CPU0_SA_DQS_DN<7>")
	)
	(arc
		(start 337.417664 -267.431266)
		(mid 337.13775 -267.507035)
		(end 336.857086 -267.43406)
		(width 0.088646)
		(layer "In4.Cu")
		(net "M_C_CPU0_SA_DQS_DN<7>")
	)
	(arc
		(start 341.162132 -268.0716)
		(mid 340.977659 -267.920235)
		(end 340.84895 -267.719302)
		(width 0.088646)
		(layer "In4.Cu")
		(net "M_C_CPU0_SA_DQS_DN<7>")
	)
	(arc
		(start 335.91246 -267.43152)
		(mid 335.725262 -267.381377)
		(end 335.538064 -267.43152)
		(width 0.088646)
		(layer "In4.Cu")
		(net "M_C_CPU0_SA_DQS_DN<7>")
	)
	(arc
		(start 339.297264 -267.431266)
		(mid 339.018941 -267.507025)
		(end 338.73948 -267.435584)
		(width 0.088646)
		(layer "In4.Cu")
		(net "M_C_CPU0_SA_DQS_DN<7>")
	)
	(arc
		(start 336.477864 -267.43152)
		(mid 336.195162 -267.507262)
		(end 335.91246 -267.43152)
		(width 0.088646)
		(layer "In4.Cu")
		(net "M_C_CPU0_SA_DQS_DN<7>")
	)
	(arc
		(start 333.09306 -267.43152)
		(mid 333.002518 -267.394017)
		(end 332.905354 -267.381228)
		(width 0.088646)
		(layer "In4.Cu")
		(net "M_C_CPU0_SA_DQS_DN<7>")
	)
	(arc
		(start 335.538064 -267.43152)
		(mid 335.255362 -267.507262)
		(end 334.97266 -267.43152)
		(width 0.088646)
		(layer "In4.Cu")
		(net "M_C_CPU0_SA_DQS_DN<7>")
	)
	(arc
		(start 337.792314 -267.431266)
		(mid 337.605006 -267.381157)
		(end 337.417664 -267.431266)
		(width 0.088646)
		(layer "In4.Cu")
		(net "M_C_CPU0_SA_DQS_DN<7>")
	)
	(arc
		(start 334.598264 -267.43152)
		(mid 334.315562 -267.507262)
		(end 334.03286 -267.43152)
		(width 0.088646)
		(layer "In4.Cu")
		(net "M_C_CPU0_SA_DQS_DN<7>")
	)
	(arc
		(start 336.85226 -267.43152)
		(mid 336.665062 -267.381377)
		(end 336.477864 -267.43152)
		(width 0.088646)
		(layer "In4.Cu")
		(net "M_C_CPU0_SA_DQS_DN<7>")
	)
	(arc
		(start 342.303862 -267.755878)
		(mid 341.918102 -267.896109)
		(end 341.55126 -268.080236)
		(width 0.088646)
		(layer "In4.Cu")
		(net "M_C_CPU0_SA_DQS_DN<7>")
	)
	(arc
		(start 334.97266 -267.43152)
		(mid 334.785462 -267.381377)
		(end 334.598264 -267.43152)
		(width 0.088646)
		(layer "In4.Cu")
		(net "M_C_CPU0_SA_DQS_DN<7>")
	)
	(arc
		(start 338.357464 -267.431266)
		(mid 338.078117 -267.507032)
		(end 337.797902 -267.434568)
		(width 0.088646)
		(layer "In4.Cu")
		(net "M_C_CPU0_SA_DQS_DN<7>")
	)
	(arc
		(start 341.55126 -268.080236)
		(mid 341.364062 -268.130379)
		(end 341.176864 -268.080236)
		(width 0.088646)
		(layer "In4.Cu")
		(net "M_C_CPU0_SA_DQS_DN<7>")
	)
	(arc
		(start 338.727542 -267.428726)
		(mid 338.542157 -267.381088)
		(end 338.357464 -267.431266)
		(width 0.088646)
		(layer "In4.Cu")
		(net "M_C_CPU0_SA_DQS_DN<7>")
	)
	(arc
		(start 339.667342 -267.428726)
		(mid 339.481957 -267.381088)
		(end 339.297264 -267.431266)
		(width 0.088646)
		(layer "In4.Cu")
		(net "M_C_CPU0_SA_DQS_DN<7>")
	)
	(arc
		(start 340.237064 -267.431266)
		(mid 339.958741 -267.507025)
		(end 339.67928 -267.435584)
		(width 0.088646)
		(layer "In4.Cu")
		(net "M_C_CPU0_SA_DQS_DN<7>")
	)
	(arc
		(start 334.03286 -267.43152)
		(mid 333.845662 -267.381377)
		(end 333.658464 -267.43152)
		(width 0.088646)
		(layer "In4.Cu")
		(net "M_C_CPU0_SA_DQS_DN<7>")
	)
	(arc
		(start 340.84895 -267.719302)
		(mid 340.814553 -267.590036)
		(end 340.720426 -267.49502)
		(width 0.088646)
		(layer "In4.Cu")
		(net "M_C_CPU0_SA_DQS_DN<7>")
	)
	(arc
		(start 333.658464 -267.43152)
		(mid 333.375762 -267.507262)
		(end 333.09306 -267.43152)
		(width 0.088646)
		(layer "In4.Cu")
		(net "M_C_CPU0_SA_DQS_DN<7>")
	)
	(arc
		(start 340.607142 -267.428726)
		(mid 340.421757 -267.381088)
		(end 340.237064 -267.431266)
		(width 0.088646)
		(layer "In4.Cu")
		(net "M_C_CPU0_SA_DQS_DN<7>")
	)
	(segment
		(start 282.060396 -302.45558)
		(end 281.356816 -302.45558)
		(width 0.20066)
		(layer "F.Cu")
		(net "M_C_CPU0_SA_DQS_DN<6>")
	)
	(segment
		(start 276.474174 -302.45558)
		(end 276.000972 -302.45558)
		(width 0.20066)
		(layer "F.Cu")
		(net "M_C_CPU0_SA_DQS_DN<6>")
	)
	(segment
		(start 282.811982 -302.716692)
		(end 282.321508 -302.716692)
		(width 0.20066)
		(layer "F.Cu")
		(net "M_C_CPU0_SA_DQS_DN<6>")
	)
	(segment
		(start 280.316178 -302.030638)
		(end 280.055066 -302.29175)
		(width 0.20066)
		(layer "F.Cu")
		(net "M_C_CPU0_SA_DQS_DN<6>")
	)
	(segment
		(start 276.896576 -302.033178)
		(end 276.474174 -302.45558)
		(width 0.20066)
		(layer "F.Cu")
		(net "M_C_CPU0_SA_DQS_DN<6>")
	)
	(segment
		(start 277.404576 -302.301402)
		(end 277.136352 -302.033178)
		(width 0.20066)
		(layer "F.Cu")
		(net "M_C_CPU0_SA_DQS_DN<6>")
	)
	(segment
		(start 279.912826 -302.29175)
		(end 277.83536 -302.29175)
		(width 0.1016)
		(layer "F.Cu")
		(net "M_C_CPU0_SA_DQS_DN<6>")
	)
	(segment
		(start 283.916882 -302.716692)
		(end 282.811982 -302.716692)
		(width 0.20066)
		(layer "F.Cu")
		(net "M_C_CPU0_SA_DQS_DN<6>")
	)
	(segment
		(start 277.589234 -302.301402)
		(end 277.58771 -302.301402)
		(width 0.101854)
		(layer "F.Cu")
		(net "M_C_CPU0_SA_DQS_DN<6>")
	)
	(segment
		(start 277.83536 -302.29175)
		(end 277.598886 -302.29175)
		(width 0.101854)
		(layer "F.Cu")
		(net "M_C_CPU0_SA_DQS_DN<6>")
	)
	(segment
		(start 275.73986 -302.716692)
		(end 275.268182 -302.716692)
		(width 0.20066)
		(layer "F.Cu")
		(net "M_C_CPU0_SA_DQS_DN<6>")
	)
	(segment
		(start 277.58771 -302.301402)
		(end 277.404576 -302.301402)
		(width 0.20066)
		(layer "F.Cu")
		(net "M_C_CPU0_SA_DQS_DN<6>")
	)
	(segment
		(start 276.000972 -302.45558)
		(end 275.73986 -302.716692)
		(width 0.20066)
		(layer "F.Cu")
		(net "M_C_CPU0_SA_DQS_DN<6>")
	)
	(segment
		(start 281.356816 -302.45558)
		(end 280.7208 -302.030638)
		(width 0.20066)
		(layer "F.Cu")
		(net "M_C_CPU0_SA_DQS_DN<6>")
	)
	(segment
		(start 280.7208 -302.030638)
		(end 280.316178 -302.030638)
		(width 0.20066)
		(layer "F.Cu")
		(net "M_C_CPU0_SA_DQS_DN<6>")
	)
	(segment
		(start 277.136352 -302.033178)
		(end 276.896576 -302.033178)
		(width 0.20066)
		(layer "F.Cu")
		(net "M_C_CPU0_SA_DQS_DN<6>")
	)
	(segment
		(start 277.598886 -302.29175)
		(end 277.589234 -302.301402)
		(width 0.101854)
		(layer "F.Cu")
		(net "M_C_CPU0_SA_DQS_DN<6>")
	)
	(segment
		(start 345.593162 -269.66164)
		(end 345.593416 -270.19758)
		(width 0.20066)
		(layer "F.Cu")
		(net "M_C_CPU0_SA_DQS_DN<6>")
	)
	(segment
		(start 280.055066 -302.29175)
		(end 279.912826 -302.29175)
		(width 0.20066)
		(layer "F.Cu")
		(net "M_C_CPU0_SA_DQS_DN<6>")
	)
	(segment
		(start 282.321508 -302.716692)
		(end 282.060396 -302.45558)
		(width 0.20066)
		(layer "F.Cu")
		(net "M_C_CPU0_SA_DQS_DN<6>")
	)
	(segment
		(start 293.864538 -292.650926)
		(end 292.83152 -293.683944)
		(width 0.18288)
		(layer "In6.Cu")
		(net "M_C_CPU0_SA_DQS_DN<6>")
	)
	(segment
		(start 324.215252 -275.9837)
		(end 315.822076 -284.37967)
		(width 0.18288)
		(layer "In6.Cu")
		(net "M_C_CPU0_SA_DQS_DN<6>")
	)
	(segment
		(start 331.306424 -273.312128)
		(end 331.283056 -273.312128)
		(width 0.088646)
		(layer "In6.Cu")
		(net "M_C_CPU0_SA_DQS_DN<6>")
	)
	(segment
		(start 306.817014 -287.322514)
		(end 305.065684 -289.074098)
		(width 0.18288)
		(layer "In6.Cu")
		(net "M_C_CPU0_SA_DQS_DN<6>")
	)
	(segment
		(start 298.76242 -292.091872)
		(end 298.494196 -291.823648)
		(width 0.18288)
		(layer "In6.Cu")
		(net "M_C_CPU0_SA_DQS_DN<6>")
	)
	(segment
		(start 284.553152 -302.444912)
		(end 284.188662 -302.444912)
		(width 0.18288)
		(layer "In6.Cu")
		(net "M_C_CPU0_SA_DQS_DN<6>")
	)
	(segment
		(start 302.456088 -290.15563)
		(end 300.799754 -291.811964)
		(width 0.18288)
		(layer "In6.Cu")
		(net "M_C_CPU0_SA_DQS_DN<6>")
	)
	(segment
		(start 295.110408 -292.94201)
		(end 294.706548 -292.94201)
		(width 0.18288)
		(layer "In6.Cu")
		(net "M_C_CPU0_SA_DQS_DN<6>")
	)
	(segment
		(start 291.224462 -293.683944)
		(end 289.645344 -295.263062)
		(width 0.18288)
		(layer "In6.Cu")
		(net "M_C_CPU0_SA_DQS_DN<6>")
	)
	(segment
		(start 307.126386 -287.115758)
		(end 306.817014 -287.322514)
		(width 0.18288)
		(layer "In6.Cu")
		(net "M_C_CPU0_SA_DQS_DN<6>")
	)
	(segment
		(start 342.975946 -269.881858)
		(end 342.961214 -269.873222)
		(width 0.088646)
		(layer "In6.Cu")
		(net "M_C_CPU0_SA_DQS_DN<6>")
	)
	(segment
		(start 332.36916 -272.139156)
		(end 331.922882 -272.585434)
		(width 0.088646)
		(layer "In6.Cu")
		(net "M_C_CPU0_SA_DQS_DN<6>")
	)
	(segment
		(start 344.258392 -270.079724)
		(end 343.90076 -269.873222)
		(width 0.088646)
		(layer "In6.Cu")
		(net "M_C_CPU0_SA_DQS_DN<6>")
	)
	(segment
		(start 334.880712 -270.19758)
		(end 334.880712 -270.207486)
		(width 0.088646)
		(layer "In6.Cu")
		(net "M_C_CPU0_SA_DQS_DN<6>")
	)
	(segment
		(start 312.432192 -285.971996)
		(end 311.229756 -285.971996)
		(width 0.18288)
		(layer "In6.Cu")
		(net "M_C_CPU0_SA_DQS_DN<6>")
	)
	(segment
		(start 344.842846 -270.520922)
		(end 344.840814 -270.521938)
		(width 0.088646)
		(layer "In6.Cu")
		(net "M_C_CPU0_SA_DQS_DN<6>")
	)
	(segment
		(start 287.882584 -301.09033)
		(end 286.380936 -301.712376)
		(width 0.18288)
		(layer "In6.Cu")
		(net "M_C_CPU0_SA_DQS_DN<6>")
	)
	(segment
		(start 295.390316 -292.662102)
		(end 295.110408 -292.94201)
		(width 0.18288)
		(layer "In6.Cu")
		(net "M_C_CPU0_SA_DQS_DN<6>")
	)
	(segment
		(start 331.643228 -273.252184)
		(end 331.366368 -273.252184)
		(width 0.088646)
		(layer "In6.Cu")
		(net "M_C_CPU0_SA_DQS_DN<6>")
	)
	(segment
		(start 333.471012 -271.016222)
		(end 333.470758 -271.016476)
		(width 0.088646)
		(layer "In6.Cu")
		(net "M_C_CPU0_SA_DQS_DN<6>")
	)
	(segment
		(start 297.458384 -292.297104)
		(end 296.577766 -292.662102)
		(width 0.18288)
		(layer "In6.Cu")
		(net "M_C_CPU0_SA_DQS_DN<6>")
	)
	(segment
		(start 284.748224 -302.639984)
		(end 284.553152 -302.444912)
		(width 0.18288)
		(layer "In6.Cu")
		(net "M_C_CPU0_SA_DQS_DN<6>")
	)
	(segment
		(start 297.93184 -291.823648)
		(end 297.458384 -292.297104)
		(width 0.18288)
		(layer "In6.Cu")
		(net "M_C_CPU0_SA_DQS_DN<6>")
	)
	(segment
		(start 335.068164 -269.873222)
		(end 335.059274 -269.878302)
		(width 0.088646)
		(layer "In6.Cu")
		(net "M_C_CPU0_SA_DQS_DN<6>")
	)
	(segment
		(start 344.278966 -270.099536)
		(end 344.258392 -270.079724)
		(width 0.088646)
		(layer "In6.Cu")
		(net "M_C_CPU0_SA_DQS_DN<6>")
	)
	(segment
		(start 344.870786 -270.504666)
		(end 344.842846 -270.520922)
		(width 0.088646)
		(layer "In6.Cu")
		(net "M_C_CPU0_SA_DQS_DN<6>")
	)
	(segment
		(start 332.36916 -271.912588)
		(end 332.36916 -272.139156)
		(width 0.088646)
		(layer "In6.Cu")
		(net "M_C_CPU0_SA_DQS_DN<6>")
	)
	(segment
		(start 345.593416 -270.19758)
		(end 344.870786 -270.504666)
		(width 0.088646)
		(layer "In6.Cu")
		(net "M_C_CPU0_SA_DQS_DN<6>")
	)
	(segment
		(start 288.71291 -300.260004)
		(end 287.882584 -301.09033)
		(width 0.18288)
		(layer "In6.Cu")
		(net "M_C_CPU0_SA_DQS_DN<6>")
	)
	(segment
		(start 285.453328 -302.639984)
		(end 284.748224 -302.639984)
		(width 0.18288)
		(layer "In6.Cu")
		(net "M_C_CPU0_SA_DQS_DN<6>")
	)
	(segment
		(start 338.272374 -269.879318)
		(end 338.26196 -269.873222)
		(width 0.088646)
		(layer "In6.Cu")
		(net "M_C_CPU0_SA_DQS_DN<6>")
	)
	(segment
		(start 294.706548 -292.94201)
		(end 294.415464 -292.650926)
		(width 0.18288)
		(layer "In6.Cu")
		(net "M_C_CPU0_SA_DQS_DN<6>")
	)
	(segment
		(start 311.229756 -285.971996)
		(end 310.239664 -286.962088)
		(width 0.18288)
		(layer "In6.Cu")
		(net "M_C_CPU0_SA_DQS_DN<6>")
	)
	(segment
		(start 332.90637 -271.576546)
		(end 332.705202 -271.576546)
		(width 0.088646)
		(layer "In6.Cu")
		(net "M_C_CPU0_SA_DQS_DN<6>")
	)
	(segment
		(start 307.497226 -286.962088)
		(end 307.126386 -287.115758)
		(width 0.18288)
		(layer "In6.Cu")
		(net "M_C_CPU0_SA_DQS_DN<6>")
	)
	(segment
		(start 331.922882 -272.585434)
		(end 331.922882 -272.97253)
		(width 0.088646)
		(layer "In6.Cu")
		(net "M_C_CPU0_SA_DQS_DN<6>")
	)
	(segment
		(start 331.283056 -273.312128)
		(end 330.66482 -273.312128)
		(width 0.18288)
		(layer "In6.Cu")
		(net "M_C_CPU0_SA_DQS_DN<6>")
	)
	(segment
		(start 296.577766 -292.662102)
		(end 295.390316 -292.662102)
		(width 0.18288)
		(layer "In6.Cu")
		(net "M_C_CPU0_SA_DQS_DN<6>")
	)
	(segment
		(start 331.366368 -273.252184)
		(end 331.306424 -273.312128)
		(width 0.088646)
		(layer "In6.Cu")
		(net "M_C_CPU0_SA_DQS_DN<6>")
	)
	(segment
		(start 333.471012 -271.011396)
		(end 333.471012 -271.016222)
		(width 0.088646)
		(layer "In6.Cu")
		(net "M_C_CPU0_SA_DQS_DN<6>")
	)
	(segment
		(start 342.036146 -269.881858)
		(end 342.021414 -269.873222)
		(width 0.088646)
		(layer "In6.Cu")
		(net "M_C_CPU0_SA_DQS_DN<6>")
	)
	(segment
		(start 299.530008 -291.811964)
		(end 299.2501 -292.091872)
		(width 0.18288)
		(layer "In6.Cu")
		(net "M_C_CPU0_SA_DQS_DN<6>")
	)
	(segment
		(start 330.66482 -273.312128)
		(end 324.215252 -275.9837)
		(width 0.18288)
		(layer "In6.Cu")
		(net "M_C_CPU0_SA_DQS_DN<6>")
	)
	(segment
		(start 344.466418 -270.521938)
		(end 344.457528 -270.516858)
		(width 0.088646)
		(layer "In6.Cu")
		(net "M_C_CPU0_SA_DQS_DN<6>")
	)
	(segment
		(start 286.380936 -301.712376)
		(end 285.453328 -302.639984)
		(width 0.18288)
		(layer "In6.Cu")
		(net "M_C_CPU0_SA_DQS_DN<6>")
	)
	(segment
		(start 331.922882 -272.97253)
		(end 331.643228 -273.252184)
		(width 0.088646)
		(layer "In6.Cu")
		(net "M_C_CPU0_SA_DQS_DN<6>")
	)
	(segment
		(start 288.71291 -295.645332)
		(end 288.71291 -300.260004)
		(width 0.18288)
		(layer "In6.Cu")
		(net "M_C_CPU0_SA_DQS_DN<6>")
	)
	(segment
		(start 292.83152 -293.683944)
		(end 291.224462 -293.683944)
		(width 0.18288)
		(layer "In6.Cu")
		(net "M_C_CPU0_SA_DQS_DN<6>")
	)
	(segment
		(start 289.645344 -295.263062)
		(end 289.09518 -295.263062)
		(width 0.18288)
		(layer "In6.Cu")
		(net "M_C_CPU0_SA_DQS_DN<6>")
	)
	(segment
		(start 339.767164 -269.873222)
		(end 339.75675 -269.879318)
		(width 0.088646)
		(layer "In6.Cu")
		(net "M_C_CPU0_SA_DQS_DN<6>")
	)
	(segment
		(start 341.096346 -269.881858)
		(end 341.081614 -269.873222)
		(width 0.088646)
		(layer "In6.Cu")
		(net "M_C_CPU0_SA_DQS_DN<6>")
	)
	(segment
		(start 314.024518 -284.37967)
		(end 312.432192 -285.971996)
		(width 0.18288)
		(layer "In6.Cu")
		(net "M_C_CPU0_SA_DQS_DN<6>")
	)
	(segment
		(start 315.822076 -284.37967)
		(end 314.024518 -284.37967)
		(width 0.18288)
		(layer "In6.Cu")
		(net "M_C_CPU0_SA_DQS_DN<6>")
	)
	(segment
		(start 310.239664 -286.962088)
		(end 307.497226 -286.962088)
		(width 0.18288)
		(layer "In6.Cu")
		(net "M_C_CPU0_SA_DQS_DN<6>")
	)
	(segment
		(start 305.065684 -289.074098)
		(end 302.456088 -290.15563)
		(width 0.18288)
		(layer "In6.Cu")
		(net "M_C_CPU0_SA_DQS_DN<6>")
	)
	(segment
		(start 299.2501 -292.091872)
		(end 298.76242 -292.091872)
		(width 0.18288)
		(layer "In6.Cu")
		(net "M_C_CPU0_SA_DQS_DN<6>")
	)
	(segment
		(start 284.188662 -302.444912)
		(end 283.916882 -302.716692)
		(width 0.18288)
		(layer "In6.Cu")
		(net "M_C_CPU0_SA_DQS_DN<6>")
	)
	(segment
		(start 298.494196 -291.823648)
		(end 297.93184 -291.823648)
		(width 0.18288)
		(layer "In6.Cu")
		(net "M_C_CPU0_SA_DQS_DN<6>")
	)
	(segment
		(start 289.09518 -295.263062)
		(end 288.71291 -295.645332)
		(width 0.18288)
		(layer "In6.Cu")
		(net "M_C_CPU0_SA_DQS_DN<6>")
	)
	(segment
		(start 294.415464 -292.650926)
		(end 293.864538 -292.650926)
		(width 0.18288)
		(layer "In6.Cu")
		(net "M_C_CPU0_SA_DQS_DN<6>")
	)
	(segment
		(start 332.705202 -271.576546)
		(end 332.36916 -271.912588)
		(width 0.088646)
		(layer "In6.Cu")
		(net "M_C_CPU0_SA_DQS_DN<6>")
	)
	(segment
		(start 340.151974 -269.879318)
		(end 340.14156 -269.873222)
		(width 0.088646)
		(layer "In6.Cu")
		(net "M_C_CPU0_SA_DQS_DN<6>")
	)
	(segment
		(start 344.278966 -270.19758)
		(end 344.278966 -270.099536)
		(width 0.088646)
		(layer "In6.Cu")
		(net "M_C_CPU0_SA_DQS_DN<6>")
	)
	(segment
		(start 300.799754 -291.811964)
		(end 299.530008 -291.811964)
		(width 0.18288)
		(layer "In6.Cu")
		(net "M_C_CPU0_SA_DQS_DN<6>")
	)
	(segment
		(start 333.658464 -270.687038)
		(end 333.649574 -270.692118)
		(width 0.088646)
		(layer "In6.Cu")
		(net "M_C_CPU0_SA_DQS_DN<6>")
	)
	(segment
		(start 343.90076 -269.873222)
		(end 343.901014 -269.873222)
		(width 0.088646)
		(layer "In6.Cu")
		(net "M_C_CPU0_SA_DQS_DN<6>")
	)
	(arc
		(start 338.827618 -269.873222)
		(mid 338.550805 -269.949058)
		(end 338.272374 -269.879318)
		(width 0.088646)
		(layer "In6.Cu")
		(net "M_C_CPU0_SA_DQS_DN<6>")
	)
	(arc
		(start 340.14156 -269.873222)
		(mid 339.954362 -269.823079)
		(end 339.767164 -269.873222)
		(width 0.088646)
		(layer "In6.Cu")
		(net "M_C_CPU0_SA_DQS_DN<6>")
	)
	(arc
		(start 342.021414 -269.873222)
		(mid 341.834216 -269.823079)
		(end 341.647018 -269.873222)
		(width 0.088646)
		(layer "In6.Cu")
		(net "M_C_CPU0_SA_DQS_DN<6>")
	)
	(arc
		(start 339.75675 -269.879318)
		(mid 339.478572 -269.94901)
		(end 339.202014 -269.873222)
		(width 0.088646)
		(layer "In6.Cu")
		(net "M_C_CPU0_SA_DQS_DN<6>")
	)
	(arc
		(start 335.059274 -269.878302)
		(mid 334.92836 -270.014662)
		(end 334.880712 -270.19758)
		(width 0.088646)
		(layer "In6.Cu")
		(net "M_C_CPU0_SA_DQS_DN<6>")
	)
	(arc
		(start 336.947764 -269.873222)
		(mid 336.665062 -269.948964)
		(end 336.38236 -269.873222)
		(width 0.088646)
		(layer "In6.Cu")
		(net "M_C_CPU0_SA_DQS_DN<6>")
	)
	(arc
		(start 334.03286 -270.687038)
		(mid 333.845662 -270.636895)
		(end 333.658464 -270.687038)
		(width 0.088646)
		(layer "In6.Cu")
		(net "M_C_CPU0_SA_DQS_DN<6>")
	)
	(arc
		(start 341.081614 -269.873222)
		(mid 340.894416 -269.823079)
		(end 340.707218 -269.873222)
		(width 0.088646)
		(layer "In6.Cu")
		(net "M_C_CPU0_SA_DQS_DN<6>")
	)
	(arc
		(start 343.901014 -269.873222)
		(mid 343.713816 -269.823079)
		(end 343.526618 -269.873222)
		(width 0.088646)
		(layer "In6.Cu")
		(net "M_C_CPU0_SA_DQS_DN<6>")
	)
	(arc
		(start 334.598264 -270.687038)
		(mid 334.315562 -270.762814)
		(end 334.03286 -270.687038)
		(width 0.088646)
		(layer "In6.Cu")
		(net "M_C_CPU0_SA_DQS_DN<6>")
	)
	(arc
		(start 341.647018 -269.873222)
		(mid 341.372789 -269.949147)
		(end 341.096346 -269.881858)
		(width 0.088646)
		(layer "In6.Cu")
		(net "M_C_CPU0_SA_DQS_DN<6>")
	)
	(arc
		(start 340.707218 -269.873222)
		(mid 340.430405 -269.949058)
		(end 340.151974 -269.879318)
		(width 0.088646)
		(layer "In6.Cu")
		(net "M_C_CPU0_SA_DQS_DN<6>")
	)
	(arc
		(start 334.880712 -270.207486)
		(mid 334.802601 -270.484435)
		(end 334.598264 -270.687038)
		(width 0.088646)
		(layer "In6.Cu")
		(net "M_C_CPU0_SA_DQS_DN<6>")
	)
	(arc
		(start 343.526618 -269.873222)
		(mid 343.252389 -269.949147)
		(end 342.975946 -269.881858)
		(width 0.088646)
		(layer "In6.Cu")
		(net "M_C_CPU0_SA_DQS_DN<6>")
	)
	(arc
		(start 344.840814 -270.521938)
		(mid 344.653616 -270.572081)
		(end 344.466418 -270.521938)
		(width 0.088646)
		(layer "In6.Cu")
		(net "M_C_CPU0_SA_DQS_DN<6>")
	)
	(arc
		(start 338.26196 -269.873222)
		(mid 338.074762 -269.823079)
		(end 337.887564 -269.873222)
		(width 0.088646)
		(layer "In6.Cu")
		(net "M_C_CPU0_SA_DQS_DN<6>")
	)
	(arc
		(start 344.457528 -270.516858)
		(mid 344.326614 -270.380498)
		(end 344.278966 -270.19758)
		(width 0.088646)
		(layer "In6.Cu")
		(net "M_C_CPU0_SA_DQS_DN<6>")
	)
	(arc
		(start 336.38236 -269.873222)
		(mid 336.195162 -269.823079)
		(end 336.007964 -269.873222)
		(width 0.088646)
		(layer "In6.Cu")
		(net "M_C_CPU0_SA_DQS_DN<6>")
	)
	(arc
		(start 339.202014 -269.873222)
		(mid 339.014816 -269.823079)
		(end 338.827618 -269.873222)
		(width 0.088646)
		(layer "In6.Cu")
		(net "M_C_CPU0_SA_DQS_DN<6>")
	)
	(arc
		(start 333.470758 -271.016476)
		(mid 333.303716 -271.412557)
		(end 332.90637 -271.576546)
		(width 0.088646)
		(layer "In6.Cu")
		(net "M_C_CPU0_SA_DQS_DN<6>")
	)
	(arc
		(start 337.887564 -269.873222)
		(mid 337.604862 -269.948964)
		(end 337.32216 -269.873222)
		(width 0.088646)
		(layer "In6.Cu")
		(net "M_C_CPU0_SA_DQS_DN<6>")
	)
	(arc
		(start 333.649574 -270.692118)
		(mid 333.51866 -270.828478)
		(end 333.471012 -271.011396)
		(width 0.088646)
		(layer "In6.Cu")
		(net "M_C_CPU0_SA_DQS_DN<6>")
	)
	(arc
		(start 337.32216 -269.873222)
		(mid 337.134962 -269.823079)
		(end 336.947764 -269.873222)
		(width 0.088646)
		(layer "In6.Cu")
		(net "M_C_CPU0_SA_DQS_DN<6>")
	)
	(arc
		(start 342.961214 -269.873222)
		(mid 342.774016 -269.823079)
		(end 342.586818 -269.873222)
		(width 0.088646)
		(layer "In6.Cu")
		(net "M_C_CPU0_SA_DQS_DN<6>")
	)
	(arc
		(start 336.007964 -269.873222)
		(mid 335.725262 -269.948964)
		(end 335.44256 -269.873222)
		(width 0.088646)
		(layer "In6.Cu")
		(net "M_C_CPU0_SA_DQS_DN<6>")
	)
	(arc
		(start 342.586818 -269.873222)
		(mid 342.312589 -269.949147)
		(end 342.036146 -269.881858)
		(width 0.088646)
		(layer "In6.Cu")
		(net "M_C_CPU0_SA_DQS_DN<6>")
	)
	(arc
		(start 335.44256 -269.873222)
		(mid 335.255362 -269.823079)
		(end 335.068164 -269.873222)
		(width 0.088646)
		(layer "In6.Cu")
		(net "M_C_CPU0_SA_DQS_DN<6>")
	)
	(segment
		(start 275.73986 -312.066686)
		(end 275.268182 -312.066686)
		(width 0.20066)
		(layer "F.Cu")
		(net "M_C_CPU0_SA_DQS_DN<5>")
	)
	(segment
		(start 277.83536 -311.641744)
		(end 277.598886 -311.641744)
		(width 0.101854)
		(layer "F.Cu")
		(net "M_C_CPU0_SA_DQS_DN<5>")
	)
	(segment
		(start 282.321508 -312.066686)
		(end 282.060396 -311.805574)
		(width 0.20066)
		(layer "F.Cu")
		(net "M_C_CPU0_SA_DQS_DN<5>")
	)
	(segment
		(start 341.364062 -276.986746)
		(end 341.364062 -277.522432)
		(width 0.20066)
		(layer "F.Cu")
		(net "M_C_CPU0_SA_DQS_DN<5>")
	)
	(segment
		(start 283.916882 -312.066686)
		(end 282.811982 -312.066686)
		(width 0.20066)
		(layer "F.Cu")
		(net "M_C_CPU0_SA_DQS_DN<5>")
	)
	(segment
		(start 341.364316 -276.986492)
		(end 341.364062 -276.986746)
		(width 0.20066)
		(layer "F.Cu")
		(net "M_C_CPU0_SA_DQS_DN<5>")
	)
	(segment
		(start 281.356816 -311.805574)
		(end 280.7208 -311.380632)
		(width 0.20066)
		(layer "F.Cu")
		(net "M_C_CPU0_SA_DQS_DN<5>")
	)
	(segment
		(start 280.055066 -311.641744)
		(end 279.912826 -311.641744)
		(width 0.20066)
		(layer "F.Cu")
		(net "M_C_CPU0_SA_DQS_DN<5>")
	)
	(segment
		(start 277.404576 -311.651396)
		(end 277.136352 -311.383172)
		(width 0.20066)
		(layer "F.Cu")
		(net "M_C_CPU0_SA_DQS_DN<5>")
	)
	(segment
		(start 276.896576 -311.383172)
		(end 276.474174 -311.805574)
		(width 0.20066)
		(layer "F.Cu")
		(net "M_C_CPU0_SA_DQS_DN<5>")
	)
	(segment
		(start 277.136352 -311.383172)
		(end 276.896576 -311.383172)
		(width 0.20066)
		(layer "F.Cu")
		(net "M_C_CPU0_SA_DQS_DN<5>")
	)
	(segment
		(start 277.598886 -311.641744)
		(end 277.589234 -311.651396)
		(width 0.101854)
		(layer "F.Cu")
		(net "M_C_CPU0_SA_DQS_DN<5>")
	)
	(segment
		(start 276.000972 -311.805574)
		(end 275.73986 -312.066686)
		(width 0.20066)
		(layer "F.Cu")
		(net "M_C_CPU0_SA_DQS_DN<5>")
	)
	(segment
		(start 280.316178 -311.380632)
		(end 280.055066 -311.641744)
		(width 0.20066)
		(layer "F.Cu")
		(net "M_C_CPU0_SA_DQS_DN<5>")
	)
	(segment
		(start 282.060396 -311.805574)
		(end 281.356816 -311.805574)
		(width 0.20066)
		(layer "F.Cu")
		(net "M_C_CPU0_SA_DQS_DN<5>")
	)
	(segment
		(start 280.7208 -311.380632)
		(end 280.316178 -311.380632)
		(width 0.20066)
		(layer "F.Cu")
		(net "M_C_CPU0_SA_DQS_DN<5>")
	)
	(segment
		(start 282.811982 -312.066686)
		(end 282.321508 -312.066686)
		(width 0.20066)
		(layer "F.Cu")
		(net "M_C_CPU0_SA_DQS_DN<5>")
	)
	(segment
		(start 277.58771 -311.651396)
		(end 277.404576 -311.651396)
		(width 0.20066)
		(layer "F.Cu")
		(net "M_C_CPU0_SA_DQS_DN<5>")
	)
	(segment
		(start 276.474174 -311.805574)
		(end 276.000972 -311.805574)
		(width 0.20066)
		(layer "F.Cu")
		(net "M_C_CPU0_SA_DQS_DN<5>")
	)
	(segment
		(start 279.912826 -311.641744)
		(end 277.83536 -311.641744)
		(width 0.1016)
		(layer "F.Cu")
		(net "M_C_CPU0_SA_DQS_DN<5>")
	)
	(segment
		(start 277.589234 -311.651396)
		(end 277.58771 -311.651396)
		(width 0.101854)
		(layer "F.Cu")
		(net "M_C_CPU0_SA_DQS_DN<5>")
	)
	(segment
		(start 307.011578 -311.101994)
		(end 305.492658 -311.730898)
		(width 0.18288)
		(layer "In4.Cu")
		(net "M_C_CPU0_SA_DQS_DN<5>")
	)
	(segment
		(start 337.230212 -280.759662)
		(end 337.230212 -280.793698)
		(width 0.088646)
		(layer "In4.Cu")
		(net "M_C_CPU0_SA_DQS_DN<5>")
	)
	(segment
		(start 284.448504 -311.794144)
		(end 284.189424 -311.794144)
		(width 0.18288)
		(layer "In4.Cu")
		(net "M_C_CPU0_SA_DQS_DN<5>")
	)
	(segment
		(start 341.364062 -277.522432)
		(end 341.676736 -277.522432)
		(width 0.088646)
		(layer "In4.Cu")
		(net "M_C_CPU0_SA_DQS_DN<5>")
	)
	(segment
		(start 326.041766 -296.684954)
		(end 318.833246 -303.89322)
		(width 0.18288)
		(layer "In4.Cu")
		(net "M_C_CPU0_SA_DQS_DN<5>")
	)
	(segment
		(start 308.639718 -310.794146)
		(end 307.31968 -310.794146)
		(width 0.18288)
		(layer "In4.Cu")
		(net "M_C_CPU0_SA_DQS_DN<5>")
	)
	(segment
		(start 337.417664 -278.82596)
		(end 337.408774 -278.83104)
		(width 0.088646)
		(layer "In4.Cu")
		(net "M_C_CPU0_SA_DQS_DN<5>")
	)
	(segment
		(start 284.189424 -311.794144)
		(end 283.916882 -312.066686)
		(width 0.18288)
		(layer "In4.Cu")
		(net "M_C_CPU0_SA_DQS_DN<5>")
	)
	(segment
		(start 332.983586 -284.326838)
		(end 332.85684 -284.632654)
		(width 0.088646)
		(layer "In4.Cu")
		(net "M_C_CPU0_SA_DQS_DN<5>")
	)
	(segment
		(start 341.176864 -277.198074)
		(end 341.162132 -277.20671)
		(width 0.088646)
		(layer "In4.Cu")
		(net "M_C_CPU0_SA_DQS_DN<5>")
	)
	(segment
		(start 329.686158 -287.888426)
		(end 326.041766 -296.684954)
		(width 0.18288)
		(layer "In4.Cu")
		(net "M_C_CPU0_SA_DQS_DN<5>")
	)
	(segment
		(start 337.700112 -278.336502)
		(end 337.700112 -278.346408)
		(width 0.088646)
		(layer "In4.Cu")
		(net "M_C_CPU0_SA_DQS_DN<5>")
	)
	(segment
		(start 332.85684 -284.632654)
		(end 332.680818 -284.808676)
		(width 0.088646)
		(layer "In4.Cu")
		(net "M_C_CPU0_SA_DQS_DN<5>")
	)
	(segment
		(start 340.237064 -277.198074)
		(end 340.222332 -277.20671)
		(width 0.088646)
		(layer "In4.Cu")
		(net "M_C_CPU0_SA_DQS_DN<5>")
	)
	(segment
		(start 311.094882 -311.203086)
		(end 310.685942 -310.794146)
		(width 0.18288)
		(layer "In4.Cu")
		(net "M_C_CPU0_SA_DQS_DN<5>")
	)
	(segment
		(start 304.456846 -311.730898)
		(end 303.120044 -313.0677)
		(width 0.18288)
		(layer "In4.Cu")
		(net "M_C_CPU0_SA_DQS_DN<5>")
	)
	(segment
		(start 299.449744 -313.0677)
		(end 299.175678 -313.341766)
		(width 0.18288)
		(layer "In4.Cu")
		(net "M_C_CPU0_SA_DQS_DN<5>")
	)
	(segment
		(start 318.833246 -305.036474)
		(end 312.666634 -311.203086)
		(width 0.18288)
		(layer "In4.Cu")
		(net "M_C_CPU0_SA_DQS_DN<5>")
	)
	(segment
		(start 312.666634 -311.203086)
		(end 311.094882 -311.203086)
		(width 0.18288)
		(layer "In4.Cu")
		(net "M_C_CPU0_SA_DQS_DN<5>")
	)
	(segment
		(start 336.938874 -280.283412)
		(end 336.947764 -280.288492)
		(width 0.088646)
		(layer "In4.Cu")
		(net "M_C_CPU0_SA_DQS_DN<5>")
	)
	(segment
		(start 292.540436 -313.070494)
		(end 291.882068 -312.412126)
		(width 0.18288)
		(layer "In4.Cu")
		(net "M_C_CPU0_SA_DQS_DN<5>")
	)
	(segment
		(start 336.943192 -281.270456)
		(end 336.939128 -281.272742)
		(width 0.088646)
		(layer "In4.Cu")
		(net "M_C_CPU0_SA_DQS_DN<5>")
	)
	(segment
		(start 309.437278 -310.794146)
		(end 309.312818 -310.918606)
		(width 0.18288)
		(layer "In4.Cu")
		(net "M_C_CPU0_SA_DQS_DN<5>")
	)
	(segment
		(start 296.985436 -313.929014)
		(end 295.3385 -313.929014)
		(width 0.18288)
		(layer "In4.Cu")
		(net "M_C_CPU0_SA_DQS_DN<5>")
	)
	(segment
		(start 338.356702 -277.198582)
		(end 338.348828 -277.203154)
		(width 0.088646)
		(layer "In4.Cu")
		(net "M_C_CPU0_SA_DQS_DN<5>")
	)
	(segment
		(start 289.105594 -312.127646)
		(end 284.782006 -312.127646)
		(width 0.18288)
		(layer "In4.Cu")
		(net "M_C_CPU0_SA_DQS_DN<5>")
	)
	(segment
		(start 332.680818 -284.893512)
		(end 332.652624 -284.921706)
		(width 0.088646)
		(layer "In4.Cu")
		(net "M_C_CPU0_SA_DQS_DN<5>")
	)
	(segment
		(start 318.833246 -303.89322)
		(end 318.833246 -305.036474)
		(width 0.18288)
		(layer "In4.Cu")
		(net "M_C_CPU0_SA_DQS_DN<5>")
	)
	(segment
		(start 337.887564 -278.012144)
		(end 337.878674 -278.017224)
		(width 0.088646)
		(layer "In4.Cu")
		(net "M_C_CPU0_SA_DQS_DN<5>")
	)
	(segment
		(start 335.922874 -282.087574)
		(end 335.91246 -282.081478)
		(width 0.088646)
		(layer "In4.Cu")
		(net "M_C_CPU0_SA_DQS_DN<5>")
	)
	(segment
		(start 336.948018 -281.267662)
		(end 336.947002 -281.26817)
		(width 0.088646)
		(layer "In4.Cu")
		(net "M_C_CPU0_SA_DQS_DN<5>")
	)
	(segment
		(start 333.415132 -283.895038)
		(end 332.983586 -284.326838)
		(width 0.088646)
		(layer "In4.Cu")
		(net "M_C_CPU0_SA_DQS_DN<5>")
	)
	(segment
		(start 338.742528 -277.20417)
		(end 338.732114 -277.198074)
		(width 0.088646)
		(layer "In4.Cu")
		(net "M_C_CPU0_SA_DQS_DN<5>")
	)
	(segment
		(start 291.882068 -312.412126)
		(end 289.390074 -312.412126)
		(width 0.18288)
		(layer "In4.Cu")
		(net "M_C_CPU0_SA_DQS_DN<5>")
	)
	(segment
		(start 292.992048 -313.070494)
		(end 292.540436 -313.070494)
		(width 0.18288)
		(layer "In4.Cu")
		(net "M_C_CPU0_SA_DQS_DN<5>")
	)
	(segment
		(start 297.858434 -313.056016)
		(end 296.985436 -313.929014)
		(width 0.18288)
		(layer "In4.Cu")
		(net "M_C_CPU0_SA_DQS_DN<5>")
	)
	(segment
		(start 309.312818 -310.918606)
		(end 308.764178 -310.918606)
		(width 0.18288)
		(layer "In4.Cu")
		(net "M_C_CPU0_SA_DQS_DN<5>")
	)
	(segment
		(start 298.525184 -313.056016)
		(end 297.858434 -313.056016)
		(width 0.18288)
		(layer "In4.Cu")
		(net "M_C_CPU0_SA_DQS_DN<5>")
	)
	(segment
		(start 336.947002 -281.26817)
		(end 336.943192 -281.270456)
		(width 0.088646)
		(layer "In4.Cu")
		(net "M_C_CPU0_SA_DQS_DN<5>")
	)
	(segment
		(start 303.120044 -313.0677)
		(end 299.449744 -313.0677)
		(width 0.18288)
		(layer "In4.Cu")
		(net "M_C_CPU0_SA_DQS_DN<5>")
	)
	(segment
		(start 308.764178 -310.918606)
		(end 308.639718 -310.794146)
		(width 0.18288)
		(layer "In4.Cu")
		(net "M_C_CPU0_SA_DQS_DN<5>")
	)
	(segment
		(start 294.710358 -314.191904)
		(end 294.427402 -313.908948)
		(width 0.18288)
		(layer "In4.Cu")
		(net "M_C_CPU0_SA_DQS_DN<5>")
	)
	(segment
		(start 332.680818 -284.808676)
		(end 332.680818 -284.893512)
		(width 0.088646)
		(layer "In4.Cu")
		(net "M_C_CPU0_SA_DQS_DN<5>")
	)
	(segment
		(start 294.427402 -313.908948)
		(end 293.830502 -313.908948)
		(width 0.18288)
		(layer "In4.Cu")
		(net "M_C_CPU0_SA_DQS_DN<5>")
	)
	(segment
		(start 295.07561 -314.191904)
		(end 294.710358 -314.191904)
		(width 0.18288)
		(layer "In4.Cu")
		(net "M_C_CPU0_SA_DQS_DN<5>")
	)
	(segment
		(start 289.390074 -312.412126)
		(end 289.105594 -312.127646)
		(width 0.18288)
		(layer "In4.Cu")
		(net "M_C_CPU0_SA_DQS_DN<5>")
	)
	(segment
		(start 307.31968 -310.794146)
		(end 307.011578 -311.101994)
		(width 0.18288)
		(layer "In4.Cu")
		(net "M_C_CPU0_SA_DQS_DN<5>")
	)
	(segment
		(start 299.175678 -313.341766)
		(end 298.810934 -313.341766)
		(width 0.18288)
		(layer "In4.Cu")
		(net "M_C_CPU0_SA_DQS_DN<5>")
	)
	(segment
		(start 298.810934 -313.341766)
		(end 298.525184 -313.056016)
		(width 0.18288)
		(layer "In4.Cu")
		(net "M_C_CPU0_SA_DQS_DN<5>")
	)
	(segment
		(start 338.170266 -277.522432)
		(end 338.170266 -277.530052)
		(width 0.088646)
		(layer "In4.Cu")
		(net "M_C_CPU0_SA_DQS_DN<5>")
	)
	(segment
		(start 295.3385 -313.929014)
		(end 295.07561 -314.191904)
		(width 0.18288)
		(layer "In4.Cu")
		(net "M_C_CPU0_SA_DQS_DN<5>")
	)
	(segment
		(start 333.940912 -283.219906)
		(end 333.940912 -283.229812)
		(width 0.088646)
		(layer "In4.Cu")
		(net "M_C_CPU0_SA_DQS_DN<5>")
	)
	(segment
		(start 336.947764 -279.639776)
		(end 336.938874 -279.644856)
		(width 0.088646)
		(layer "In4.Cu")
		(net "M_C_CPU0_SA_DQS_DN<5>")
	)
	(segment
		(start 293.830502 -313.908948)
		(end 292.992048 -313.070494)
		(width 0.18288)
		(layer "In4.Cu")
		(net "M_C_CPU0_SA_DQS_DN<5>")
	)
	(segment
		(start 337.230212 -279.150318)
		(end 337.230212 -279.160224)
		(width 0.088646)
		(layer "In4.Cu")
		(net "M_C_CPU0_SA_DQS_DN<5>")
	)
	(segment
		(start 284.782006 -312.127646)
		(end 284.448504 -311.794144)
		(width 0.18288)
		(layer "In4.Cu")
		(net "M_C_CPU0_SA_DQS_DN<5>")
	)
	(segment
		(start 335.350866 -282.3972)
		(end 335.350866 -282.42006)
		(width 0.088646)
		(layer "In4.Cu")
		(net "M_C_CPU0_SA_DQS_DN<5>")
	)
	(segment
		(start 332.652624 -284.921706)
		(end 329.686158 -287.888426)
		(width 0.18288)
		(layer "In4.Cu")
		(net "M_C_CPU0_SA_DQS_DN<5>")
	)
	(segment
		(start 338.357718 -277.198074)
		(end 338.356702 -277.198582)
		(width 0.088646)
		(layer "In4.Cu")
		(net "M_C_CPU0_SA_DQS_DN<5>")
	)
	(segment
		(start 341.676736 -277.522432)
		(end 341.73414 -277.465028)
		(width 0.088646)
		(layer "In4.Cu")
		(net "M_C_CPU0_SA_DQS_DN<5>")
	)
	(segment
		(start 305.492658 -311.730898)
		(end 304.456846 -311.730898)
		(width 0.18288)
		(layer "In4.Cu")
		(net "M_C_CPU0_SA_DQS_DN<5>")
	)
	(segment
		(start 310.685942 -310.794146)
		(end 309.437278 -310.794146)
		(width 0.18288)
		(layer "In4.Cu")
		(net "M_C_CPU0_SA_DQS_DN<5>")
	)
	(arc
		(start 333.940912 -283.229812)
		(mid 333.862801 -283.506761)
		(end 333.658464 -283.709364)
		(width 0.088646)
		(layer "In4.Cu")
		(net "M_C_CPU0_SA_DQS_DN<5>")
	)
	(arc
		(start 337.878674 -278.017224)
		(mid 337.74776 -278.153584)
		(end 337.700112 -278.336502)
		(width 0.088646)
		(layer "In4.Cu")
		(net "M_C_CPU0_SA_DQS_DN<5>")
	)
	(arc
		(start 338.732114 -277.198074)
		(mid 338.544916 -277.147931)
		(end 338.357718 -277.198074)
		(width 0.088646)
		(layer "In4.Cu")
		(net "M_C_CPU0_SA_DQS_DN<5>")
	)
	(arc
		(start 336.938874 -279.644856)
		(mid 336.760277 -279.964134)
		(end 336.938874 -280.283412)
		(width 0.088646)
		(layer "In4.Cu")
		(net "M_C_CPU0_SA_DQS_DN<5>")
	)
	(arc
		(start 341.162132 -277.20671)
		(mid 340.885657 -277.27403)
		(end 340.61146 -277.198074)
		(width 0.088646)
		(layer "In4.Cu")
		(net "M_C_CPU0_SA_DQS_DN<5>")
	)
	(arc
		(start 336.939128 -281.272742)
		(mid 336.808214 -281.409102)
		(end 336.760566 -281.59202)
		(width 0.088646)
		(layer "In4.Cu")
		(net "M_C_CPU0_SA_DQS_DN<5>")
	)
	(arc
		(start 335.350866 -282.42006)
		(mid 335.062167 -282.899207)
		(end 334.50276 -282.895548)
		(width 0.088646)
		(layer "In4.Cu")
		(net "M_C_CPU0_SA_DQS_DN<5>")
	)
	(arc
		(start 341.73414 -277.465028)
		(mid 341.525818 -277.184874)
		(end 341.176864 -277.198074)
		(width 0.088646)
		(layer "In4.Cu")
		(net "M_C_CPU0_SA_DQS_DN<5>")
	)
	(arc
		(start 340.61146 -277.198074)
		(mid 340.424262 -277.147931)
		(end 340.237064 -277.198074)
		(width 0.088646)
		(layer "In4.Cu")
		(net "M_C_CPU0_SA_DQS_DN<5>")
	)
	(arc
		(start 337.230212 -280.793698)
		(mid 337.150842 -281.067432)
		(end 336.948018 -281.267662)
		(width 0.088646)
		(layer "In4.Cu")
		(net "M_C_CPU0_SA_DQS_DN<5>")
	)
	(arc
		(start 335.91246 -282.081478)
		(mid 335.541737 -282.079386)
		(end 335.350866 -282.3972)
		(width 0.088646)
		(layer "In4.Cu")
		(net "M_C_CPU0_SA_DQS_DN<5>")
	)
	(arc
		(start 339.297264 -277.198074)
		(mid 339.020705 -277.273817)
		(end 338.742528 -277.20417)
		(width 0.088646)
		(layer "In4.Cu")
		(net "M_C_CPU0_SA_DQS_DN<5>")
	)
	(arc
		(start 336.760566 -281.59202)
		(mid 336.483031 -282.078655)
		(end 335.922874 -282.087574)
		(width 0.088646)
		(layer "In4.Cu")
		(net "M_C_CPU0_SA_DQS_DN<5>")
	)
	(arc
		(start 339.67166 -277.198074)
		(mid 339.484462 -277.147931)
		(end 339.297264 -277.198074)
		(width 0.088646)
		(layer "In4.Cu")
		(net "M_C_CPU0_SA_DQS_DN<5>")
	)
	(arc
		(start 340.222332 -277.20671)
		(mid 339.945857 -277.27403)
		(end 339.67166 -277.198074)
		(width 0.088646)
		(layer "In4.Cu")
		(net "M_C_CPU0_SA_DQS_DN<5>")
	)
	(arc
		(start 338.348828 -277.203154)
		(mid 338.217914 -277.339514)
		(end 338.170266 -277.522432)
		(width 0.088646)
		(layer "In4.Cu")
		(net "M_C_CPU0_SA_DQS_DN<5>")
	)
	(arc
		(start 337.700112 -278.346408)
		(mid 337.622001 -278.623357)
		(end 337.417664 -278.82596)
		(width 0.088646)
		(layer "In4.Cu")
		(net "M_C_CPU0_SA_DQS_DN<5>")
	)
	(arc
		(start 337.230212 -279.160224)
		(mid 337.152101 -279.437173)
		(end 336.947764 -279.639776)
		(width 0.088646)
		(layer "In4.Cu")
		(net "M_C_CPU0_SA_DQS_DN<5>")
	)
	(arc
		(start 338.170266 -277.530052)
		(mid 338.092637 -277.808465)
		(end 337.887564 -278.012144)
		(width 0.088646)
		(layer "In4.Cu")
		(net "M_C_CPU0_SA_DQS_DN<5>")
	)
	(arc
		(start 334.50276 -282.895548)
		(mid 334.128285 -282.895594)
		(end 333.940912 -283.219906)
		(width 0.088646)
		(layer "In4.Cu")
		(net "M_C_CPU0_SA_DQS_DN<5>")
	)
	(arc
		(start 333.658464 -283.709364)
		(mid 333.530584 -283.794057)
		(end 333.415132 -283.895038)
		(width 0.088646)
		(layer "In4.Cu")
		(net "M_C_CPU0_SA_DQS_DN<5>")
	)
	(arc
		(start 337.408774 -278.83104)
		(mid 337.27786 -278.9674)
		(end 337.230212 -279.150318)
		(width 0.088646)
		(layer "In4.Cu")
		(net "M_C_CPU0_SA_DQS_DN<5>")
	)
	(arc
		(start 336.947764 -280.288492)
		(mid 337.15005 -280.487473)
		(end 337.230212 -280.759662)
		(width 0.088646)
		(layer "In4.Cu")
		(net "M_C_CPU0_SA_DQS_DN<5>")
	)
	(segment
		(start 272.491708 -274.927822)
		(end 271.977866 -274.927822)
		(width 0.20066)
		(layer "F.Cu")
		(net "M_C_CPU0_SA_DQS_DN<4>")
	)
	(segment
		(start 274.014184 -275.091652)
		(end 273.929094 -275.091652)
		(width 0.20066)
		(layer "F.Cu")
		(net "M_C_CPU0_SA_DQS_DN<4>")
	)
	(segment
		(start 278.711914 -274.66671)
		(end 278.165306 -274.66671)
		(width 0.20066)
		(layer "F.Cu")
		(net "M_C_CPU0_SA_DQS_DN<4>")
	)
	(segment
		(start 279.816814 -274.66671)
		(end 278.711914 -274.66671)
		(width 0.20066)
		(layer "F.Cu")
		(net "M_C_CPU0_SA_DQS_DN<4>")
	)
	(segment
		(start 274.155408 -275.091652)
		(end 274.014184 -275.091652)
		(width 0.101854)
		(layer "F.Cu")
		(net "M_C_CPU0_SA_DQS_DN<4>")
	)
	(segment
		(start 277.49754 -274.927822)
		(end 277.072344 -275.353018)
		(width 0.20066)
		(layer "F.Cu")
		(net "M_C_CPU0_SA_DQS_DN<4>")
	)
	(segment
		(start 271.977866 -274.927822)
		(end 271.716754 -274.66671)
		(width 0.20066)
		(layer "F.Cu")
		(net "M_C_CPU0_SA_DQS_DN<4>")
	)
	(segment
		(start 276.469094 -275.091652)
		(end 274.155408 -275.091652)
		(width 0.1016)
		(layer "F.Cu")
		(net "M_C_CPU0_SA_DQS_DN<4>")
	)
	(segment
		(start 273.929094 -275.091652)
		(end 273.667728 -275.353018)
		(width 0.20066)
		(layer "F.Cu")
		(net "M_C_CPU0_SA_DQS_DN<4>")
	)
	(segment
		(start 278.165306 -274.66671)
		(end 277.904194 -274.927822)
		(width 0.20066)
		(layer "F.Cu")
		(net "M_C_CPU0_SA_DQS_DN<4>")
	)
	(segment
		(start 276.624288 -275.091652)
		(end 276.53488 -275.091652)
		(width 0.20066)
		(layer "F.Cu")
		(net "M_C_CPU0_SA_DQS_DN<4>")
	)
	(segment
		(start 276.885654 -275.353018)
		(end 276.624288 -275.091652)
		(width 0.20066)
		(layer "F.Cu")
		(net "M_C_CPU0_SA_DQS_DN<4>")
	)
	(segment
		(start 277.904194 -274.927822)
		(end 277.49754 -274.927822)
		(width 0.20066)
		(layer "F.Cu")
		(net "M_C_CPU0_SA_DQS_DN<4>")
	)
	(segment
		(start 277.072344 -275.353018)
		(end 276.885654 -275.353018)
		(width 0.20066)
		(layer "F.Cu")
		(net "M_C_CPU0_SA_DQS_DN<4>")
	)
	(segment
		(start 343.713562 -259.894832)
		(end 343.713816 -260.430772)
		(width 0.20066)
		(layer "F.Cu")
		(net "M_C_CPU0_SA_DQS_DN<4>")
	)
	(segment
		(start 273.667728 -275.353018)
		(end 273.127724 -275.353018)
		(width 0.20066)
		(layer "F.Cu")
		(net "M_C_CPU0_SA_DQS_DN<4>")
	)
	(segment
		(start 271.716754 -274.66671)
		(end 271.168114 -274.66671)
		(width 0.20066)
		(layer "F.Cu")
		(net "M_C_CPU0_SA_DQS_DN<4>")
	)
	(segment
		(start 273.127724 -275.353018)
		(end 272.491708 -274.927822)
		(width 0.20066)
		(layer "F.Cu")
		(net "M_C_CPU0_SA_DQS_DN<4>")
	)
	(segment
		(start 276.53488 -275.091652)
		(end 276.469094 -275.091652)
		(width 0.101854)
		(layer "F.Cu")
		(net "M_C_CPU0_SA_DQS_DN<4>")
	)
	(segment
		(start 339.297518 -259.941314)
		(end 339.287104 -259.935218)
		(width 0.088646)
		(layer "In6.Cu")
		(net "M_C_CPU0_SA_DQS_DN<4>")
	)
	(segment
		(start 330.68133 -260.832092)
		(end 330.621386 -260.772148)
		(width 0.088646)
		(layer "In6.Cu")
		(net "M_C_CPU0_SA_DQS_DN<4>")
	)
	(segment
		(start 299.156374 -265.74242)
		(end 298.915074 -265.74242)
		(width 0.18288)
		(layer "In6.Cu")
		(net "M_C_CPU0_SA_DQS_DN<4>")
	)
	(segment
		(start 297.725592 -265.997182)
		(end 296.877486 -266.845288)
		(width 0.18288)
		(layer "In6.Cu")
		(net "M_C_CPU0_SA_DQS_DN<4>")
	)
	(segment
		(start 339.682328 -259.935218)
		(end 339.671914 -259.941314)
		(width 0.088646)
		(layer "In6.Cu")
		(net "M_C_CPU0_SA_DQS_DN<4>")
	)
	(segment
		(start 341.551006 -259.941314)
		(end 341.55126 -259.941314)
		(width 0.088646)
		(layer "In6.Cu")
		(net "M_C_CPU0_SA_DQS_DN<4>")
	)
	(segment
		(start 295.439084 -266.845288)
		(end 295.186608 -266.592812)
		(width 0.18288)
		(layer "In6.Cu")
		(net "M_C_CPU0_SA_DQS_DN<4>")
	)
	(segment
		(start 342.743282 -260.057392)
		(end 342.686132 -260.06425)
		(width 0.088646)
		(layer "In6.Cu")
		(net "M_C_CPU0_SA_DQS_DN<4>")
	)
	(segment
		(start 295.039034 -266.592558)
		(end 294.825674 -266.592558)
		(width 0.18288)
		(layer "In6.Cu")
		(net "M_C_CPU0_SA_DQS_DN<4>")
	)
	(segment
		(start 310.440578 -264.540746)
		(end 309.802276 -264.540746)
		(width 0.18288)
		(layer "In6.Cu")
		(net "M_C_CPU0_SA_DQS_DN<4>")
	)
	(segment
		(start 337.417664 -259.941314)
		(end 337.402932 -259.932678)
		(width 0.088646)
		(layer "In6.Cu")
		(net "M_C_CPU0_SA_DQS_DN<4>")
	)
	(segment
		(start 283.43606 -272.793206)
		(end 282.924504 -272.793206)
		(width 0.18288)
		(layer "In6.Cu")
		(net "M_C_CPU0_SA_DQS_DN<4>")
	)
	(segment
		(start 298.91482 -265.742674)
		(end 298.775628 -265.742674)
		(width 0.18288)
		(layer "In6.Cu")
		(net "M_C_CPU0_SA_DQS_DN<4>")
	)
	(segment
		(start 312.105294 -264.896346)
		(end 311.299606 -264.896346)
		(width 0.18288)
		(layer "In6.Cu")
		(net "M_C_CPU0_SA_DQS_DN<4>")
	)
	(segment
		(start 284.971998 -272.828766)
		(end 284.447234 -272.828766)
		(width 0.18288)
		(layer "In6.Cu")
		(net "M_C_CPU0_SA_DQS_DN<4>")
	)
	(segment
		(start 295.039288 -266.592812)
		(end 295.039034 -266.592558)
		(width 0.18288)
		(layer "In6.Cu")
		(net "M_C_CPU0_SA_DQS_DN<4>")
	)
	(segment
		(start 331.760576 -260.131814)
		(end 331.060298 -260.832092)
		(width 0.088646)
		(layer "In6.Cu")
		(net "M_C_CPU0_SA_DQS_DN<4>")
	)
	(segment
		(start 291.330888 -268.581886)
		(end 289.851846 -270.060674)
		(width 0.18288)
		(layer "In6.Cu")
		(net "M_C_CPU0_SA_DQS_DN<4>")
	)
	(segment
		(start 285.715456 -272.520664)
		(end 284.971998 -272.828766)
		(width 0.18288)
		(layer "In6.Cu")
		(net "M_C_CPU0_SA_DQS_DN<4>")
	)
	(segment
		(start 342.686132 -260.06425)
		(end 342.681306 -260.06171)
		(width 0.088646)
		(layer "In6.Cu")
		(net "M_C_CPU0_SA_DQS_DN<4>")
	)
	(segment
		(start 312.474102 -264.7442)
		(end 312.105294 -264.896346)
		(width 0.18288)
		(layer "In6.Cu")
		(net "M_C_CPU0_SA_DQS_DN<4>")
	)
	(segment
		(start 283.686758 -272.542508)
		(end 283.43606 -272.793206)
		(width 0.18288)
		(layer "In6.Cu")
		(net "M_C_CPU0_SA_DQS_DN<4>")
	)
	(segment
		(start 304.180494 -265.381486)
		(end 302.670464 -266.006834)
		(width 0.18288)
		(layer "In6.Cu")
		(net "M_C_CPU0_SA_DQS_DN<4>")
	)
	(segment
		(start 294.432228 -266.836144)
		(end 293.943278 -266.836144)
		(width 0.18288)
		(layer "In6.Cu")
		(net "M_C_CPU0_SA_DQS_DN<4>")
	)
	(segment
		(start 331.060298 -260.832092)
		(end 330.68133 -260.832092)
		(width 0.088646)
		(layer "In6.Cu")
		(net "M_C_CPU0_SA_DQS_DN<4>")
	)
	(segment
		(start 342.325706 -260.06171)
		(end 342.102186 -259.932932)
		(width 0.088646)
		(layer "In6.Cu")
		(net "M_C_CPU0_SA_DQS_DN<4>")
	)
	(segment
		(start 299.286676 -265.742674)
		(end 299.156374 -265.74242)
		(width 0.18288)
		(layer "In6.Cu")
		(net "M_C_CPU0_SA_DQS_DN<4>")
	)
	(segment
		(start 293.943278 -266.836144)
		(end 291.330888 -268.581886)
		(width 0.18288)
		(layer "In6.Cu")
		(net "M_C_CPU0_SA_DQS_DN<4>")
	)
	(segment
		(start 306.762658 -265.381486)
		(end 304.180494 -265.381486)
		(width 0.18288)
		(layer "In6.Cu")
		(net "M_C_CPU0_SA_DQS_DN<4>")
	)
	(segment
		(start 309.802276 -264.540746)
		(end 309.004716 -264.870946)
		(width 0.18288)
		(layer "In6.Cu")
		(net "M_C_CPU0_SA_DQS_DN<4>")
	)
	(segment
		(start 286.990282 -271.246092)
		(end 285.715456 -272.520664)
		(width 0.18288)
		(layer "In6.Cu")
		(net "M_C_CPU0_SA_DQS_DN<4>")
	)
	(segment
		(start 284.160976 -272.542508)
		(end 283.686758 -272.542508)
		(width 0.18288)
		(layer "In6.Cu")
		(net "M_C_CPU0_SA_DQS_DN<4>")
	)
	(segment
		(start 294.825674 -266.592558)
		(end 294.82542 -266.592812)
		(width 0.18288)
		(layer "In6.Cu")
		(net "M_C_CPU0_SA_DQS_DN<4>")
	)
	(segment
		(start 330.598018 -260.772148)
		(end 329.213464 -260.772148)
		(width 0.18288)
		(layer "In6.Cu")
		(net "M_C_CPU0_SA_DQS_DN<4>")
	)
	(segment
		(start 296.877486 -266.845288)
		(end 295.439084 -266.845288)
		(width 0.18288)
		(layer "In6.Cu")
		(net "M_C_CPU0_SA_DQS_DN<4>")
	)
	(segment
		(start 294.67556 -266.592812)
		(end 294.432228 -266.836144)
		(width 0.18288)
		(layer "In6.Cu")
		(net "M_C_CPU0_SA_DQS_DN<4>")
	)
	(segment
		(start 280.08453 -274.934426)
		(end 279.816814 -274.66671)
		(width 0.18288)
		(layer "In6.Cu")
		(net "M_C_CPU0_SA_DQS_DN<4>")
	)
	(segment
		(start 313.243722 -263.974326)
		(end 312.474102 -264.7442)
		(width 0.18288)
		(layer "In6.Cu")
		(net "M_C_CPU0_SA_DQS_DN<4>")
	)
	(segment
		(start 299.550836 -266.006834)
		(end 299.286676 -265.742674)
		(width 0.18288)
		(layer "In6.Cu")
		(net "M_C_CPU0_SA_DQS_DN<4>")
	)
	(segment
		(start 289.851846 -270.060674)
		(end 286.990282 -271.246092)
		(width 0.18288)
		(layer "In6.Cu")
		(net "M_C_CPU0_SA_DQS_DN<4>")
	)
	(segment
		(start 294.82542 -266.592812)
		(end 294.67556 -266.592812)
		(width 0.18288)
		(layer "In6.Cu")
		(net "M_C_CPU0_SA_DQS_DN<4>")
	)
	(segment
		(start 317.861696 -262.065516)
		(end 313.243722 -263.974326)
		(width 0.18288)
		(layer "In6.Cu")
		(net "M_C_CPU0_SA_DQS_DN<4>")
	)
	(segment
		(start 311.299606 -264.896346)
		(end 310.440578 -264.540746)
		(width 0.18288)
		(layer "In6.Cu")
		(net "M_C_CPU0_SA_DQS_DN<4>")
	)
	(segment
		(start 342.681306 -260.06171)
		(end 342.325706 -260.06171)
		(width 0.088646)
		(layer "In6.Cu")
		(net "M_C_CPU0_SA_DQS_DN<4>")
	)
	(segment
		(start 332.03642 -260.030468)
		(end 331.934058 -260.131814)
		(width 0.088646)
		(layer "In6.Cu")
		(net "M_C_CPU0_SA_DQS_DN<4>")
	)
	(segment
		(start 330.621386 -260.772148)
		(end 330.598018 -260.772148)
		(width 0.088646)
		(layer "In6.Cu")
		(net "M_C_CPU0_SA_DQS_DN<4>")
	)
	(segment
		(start 302.670464 -266.006834)
		(end 299.550836 -266.006834)
		(width 0.18288)
		(layer "In6.Cu")
		(net "M_C_CPU0_SA_DQS_DN<4>")
	)
	(segment
		(start 307.737002 -265.785346)
		(end 306.762658 -265.381486)
		(width 0.18288)
		(layer "In6.Cu")
		(net "M_C_CPU0_SA_DQS_DN<4>")
	)
	(segment
		(start 298.52112 -265.997182)
		(end 297.725592 -265.997182)
		(width 0.18288)
		(layer "In6.Cu")
		(net "M_C_CPU0_SA_DQS_DN<4>")
	)
	(segment
		(start 326.090534 -262.065516)
		(end 317.861696 -262.065516)
		(width 0.18288)
		(layer "In6.Cu")
		(net "M_C_CPU0_SA_DQS_DN<4>")
	)
	(segment
		(start 341.176864 -259.941314)
		(end 341.162132 -259.932678)
		(width 0.088646)
		(layer "In6.Cu")
		(net "M_C_CPU0_SA_DQS_DN<4>")
	)
	(segment
		(start 338.357464 -259.941314)
		(end 338.342732 -259.932678)
		(width 0.088646)
		(layer "In6.Cu")
		(net "M_C_CPU0_SA_DQS_DN<4>")
	)
	(segment
		(start 343.372948 -260.340856)
		(end 342.947752 -260.099048)
		(width 0.088646)
		(layer "In6.Cu")
		(net "M_C_CPU0_SA_DQS_DN<4>")
	)
	(segment
		(start 308.09057 -265.785346)
		(end 307.737002 -265.785346)
		(width 0.18288)
		(layer "In6.Cu")
		(net "M_C_CPU0_SA_DQS_DN<4>")
	)
	(segment
		(start 282.924504 -272.793206)
		(end 280.783284 -274.934426)
		(width 0.18288)
		(layer "In6.Cu")
		(net "M_C_CPU0_SA_DQS_DN<4>")
	)
	(segment
		(start 284.447234 -272.828766)
		(end 284.160976 -272.542508)
		(width 0.18288)
		(layer "In6.Cu")
		(net "M_C_CPU0_SA_DQS_DN<4>")
	)
	(segment
		(start 280.783284 -274.934426)
		(end 280.08453 -274.934426)
		(width 0.18288)
		(layer "In6.Cu")
		(net "M_C_CPU0_SA_DQS_DN<4>")
	)
	(segment
		(start 298.915074 -265.74242)
		(end 298.91482 -265.742674)
		(width 0.18288)
		(layer "In6.Cu")
		(net "M_C_CPU0_SA_DQS_DN<4>")
	)
	(segment
		(start 295.186608 -266.592812)
		(end 295.039288 -266.592812)
		(width 0.18288)
		(layer "In6.Cu")
		(net "M_C_CPU0_SA_DQS_DN<4>")
	)
	(segment
		(start 309.004716 -264.870946)
		(end 308.09057 -265.785346)
		(width 0.18288)
		(layer "In6.Cu")
		(net "M_C_CPU0_SA_DQS_DN<4>")
	)
	(segment
		(start 331.934058 -260.131814)
		(end 331.760576 -260.131814)
		(width 0.088646)
		(layer "In6.Cu")
		(net "M_C_CPU0_SA_DQS_DN<4>")
	)
	(segment
		(start 329.213464 -260.772148)
		(end 326.090534 -262.065516)
		(width 0.18288)
		(layer "In6.Cu")
		(net "M_C_CPU0_SA_DQS_DN<4>")
	)
	(segment
		(start 298.775628 -265.742674)
		(end 298.52112 -265.997182)
		(width 0.18288)
		(layer "In6.Cu")
		(net "M_C_CPU0_SA_DQS_DN<4>")
	)
	(arc
		(start 334.97266 -259.941314)
		(mid 334.785462 -259.991457)
		(end 334.598264 -259.941314)
		(width 0.088646)
		(layer "In6.Cu")
		(net "M_C_CPU0_SA_DQS_DN<4>")
	)
	(arc
		(start 339.287104 -259.935218)
		(mid 339.008672 -259.865372)
		(end 338.73186 -259.941314)
		(width 0.088646)
		(layer "In6.Cu")
		(net "M_C_CPU0_SA_DQS_DN<4>")
	)
	(arc
		(start 343.713816 -260.430772)
		(mid 343.537551 -260.407917)
		(end 343.372948 -260.340856)
		(width 0.088646)
		(layer "In6.Cu")
		(net "M_C_CPU0_SA_DQS_DN<4>")
	)
	(arc
		(start 333.09306 -259.941314)
		(mid 332.905862 -259.991457)
		(end 332.718664 -259.941314)
		(width 0.088646)
		(layer "In6.Cu")
		(net "M_C_CPU0_SA_DQS_DN<4>")
	)
	(arc
		(start 342.102186 -259.932932)
		(mid 341.825521 -259.865461)
		(end 341.551006 -259.941314)
		(width 0.088646)
		(layer "In6.Cu")
		(net "M_C_CPU0_SA_DQS_DN<4>")
	)
	(arc
		(start 332.718664 -259.941314)
		(mid 332.435962 -259.865538)
		(end 332.15326 -259.941314)
		(width 0.088646)
		(layer "In6.Cu")
		(net "M_C_CPU0_SA_DQS_DN<4>")
	)
	(arc
		(start 336.477864 -259.941314)
		(mid 336.195162 -259.865538)
		(end 335.91246 -259.941314)
		(width 0.088646)
		(layer "In6.Cu")
		(net "M_C_CPU0_SA_DQS_DN<4>")
	)
	(arc
		(start 337.402932 -259.932678)
		(mid 337.126457 -259.865358)
		(end 336.85226 -259.941314)
		(width 0.088646)
		(layer "In6.Cu")
		(net "M_C_CPU0_SA_DQS_DN<4>")
	)
	(arc
		(start 337.79206 -259.941314)
		(mid 337.604862 -259.991457)
		(end 337.417664 -259.941314)
		(width 0.088646)
		(layer "In6.Cu")
		(net "M_C_CPU0_SA_DQS_DN<4>")
	)
	(arc
		(start 332.088998 -259.984494)
		(mid 332.061999 -260.006669)
		(end 332.03642 -260.030468)
		(width 0.088646)
		(layer "In6.Cu")
		(net "M_C_CPU0_SA_DQS_DN<4>")
	)
	(arc
		(start 332.15326 -259.941314)
		(mid 332.12039 -259.961804)
		(end 332.088998 -259.984494)
		(width 0.088646)
		(layer "In6.Cu")
		(net "M_C_CPU0_SA_DQS_DN<4>")
	)
	(arc
		(start 339.671914 -259.941314)
		(mid 339.484716 -259.991457)
		(end 339.297518 -259.941314)
		(width 0.088646)
		(layer "In6.Cu")
		(net "M_C_CPU0_SA_DQS_DN<4>")
	)
	(arc
		(start 341.55126 -259.941314)
		(mid 341.364062 -259.991457)
		(end 341.176864 -259.941314)
		(width 0.088646)
		(layer "In6.Cu")
		(net "M_C_CPU0_SA_DQS_DN<4>")
	)
	(arc
		(start 342.947752 -260.099048)
		(mid 342.84891 -260.061538)
		(end 342.743282 -260.057392)
		(width 0.088646)
		(layer "In6.Cu")
		(net "M_C_CPU0_SA_DQS_DN<4>")
	)
	(arc
		(start 335.538064 -259.941314)
		(mid 335.255362 -259.865538)
		(end 334.97266 -259.941314)
		(width 0.088646)
		(layer "In6.Cu")
		(net "M_C_CPU0_SA_DQS_DN<4>")
	)
	(arc
		(start 334.03286 -259.941314)
		(mid 333.845662 -259.991457)
		(end 333.658464 -259.941314)
		(width 0.088646)
		(layer "In6.Cu")
		(net "M_C_CPU0_SA_DQS_DN<4>")
	)
	(arc
		(start 338.73186 -259.941314)
		(mid 338.544662 -259.991457)
		(end 338.357464 -259.941314)
		(width 0.088646)
		(layer "In6.Cu")
		(net "M_C_CPU0_SA_DQS_DN<4>")
	)
	(arc
		(start 335.91246 -259.941314)
		(mid 335.725262 -259.991457)
		(end 335.538064 -259.941314)
		(width 0.088646)
		(layer "In6.Cu")
		(net "M_C_CPU0_SA_DQS_DN<4>")
	)
	(arc
		(start 333.658464 -259.941314)
		(mid 333.375762 -259.865538)
		(end 333.09306 -259.941314)
		(width 0.088646)
		(layer "In6.Cu")
		(net "M_C_CPU0_SA_DQS_DN<4>")
	)
	(arc
		(start 334.598264 -259.941314)
		(mid 334.315562 -259.865538)
		(end 334.03286 -259.941314)
		(width 0.088646)
		(layer "In6.Cu")
		(net "M_C_CPU0_SA_DQS_DN<4>")
	)
	(arc
		(start 336.85226 -259.941314)
		(mid 336.665062 -259.991457)
		(end 336.477864 -259.941314)
		(width 0.088646)
		(layer "In6.Cu")
		(net "M_C_CPU0_SA_DQS_DN<4>")
	)
	(arc
		(start 340.237064 -259.941314)
		(mid 339.960505 -259.865571)
		(end 339.682328 -259.935218)
		(width 0.088646)
		(layer "In6.Cu")
		(net "M_C_CPU0_SA_DQS_DN<4>")
	)
	(arc
		(start 341.162132 -259.932678)
		(mid 340.885657 -259.865358)
		(end 340.61146 -259.941314)
		(width 0.088646)
		(layer "In6.Cu")
		(net "M_C_CPU0_SA_DQS_DN<4>")
	)
	(arc
		(start 338.342732 -259.932678)
		(mid 338.066257 -259.865358)
		(end 337.79206 -259.941314)
		(width 0.088646)
		(layer "In6.Cu")
		(net "M_C_CPU0_SA_DQS_DN<4>")
	)
	(arc
		(start 340.61146 -259.941314)
		(mid 340.424262 -259.991457)
		(end 340.237064 -259.941314)
		(width 0.088646)
		(layer "In6.Cu")
		(net "M_C_CPU0_SA_DQS_DN<4>")
	)
	(segment
		(start 277.49754 -284.277816)
		(end 277.072344 -284.703012)
		(width 0.20066)
		(layer "F.Cu")
		(net "M_C_CPU0_SA_DQS_DN<3>")
	)
	(segment
		(start 342.773762 -264.778236)
		(end 342.774016 -265.314176)
		(width 0.20066)
		(layer "F.Cu")
		(net "M_C_CPU0_SA_DQS_DN<3>")
	)
	(segment
		(start 278.165306 -284.016704)
		(end 277.904194 -284.277816)
		(width 0.20066)
		(layer "F.Cu")
		(net "M_C_CPU0_SA_DQS_DN<3>")
	)
	(segment
		(start 274.14474 -284.430978)
		(end 274.143978 -284.430978)
		(width 0.101854)
		(layer "F.Cu")
		(net "M_C_CPU0_SA_DQS_DN<3>")
	)
	(segment
		(start 276.624288 -284.441646)
		(end 276.469094 -284.441646)
		(width 0.20066)
		(layer "F.Cu")
		(net "M_C_CPU0_SA_DQS_DN<3>")
	)
	(segment
		(start 276.885654 -284.703012)
		(end 276.624288 -284.441646)
		(width 0.20066)
		(layer "F.Cu")
		(net "M_C_CPU0_SA_DQS_DN<3>")
	)
	(segment
		(start 274.143978 -284.430978)
		(end 273.939762 -284.430978)
		(width 0.20066)
		(layer "F.Cu")
		(net "M_C_CPU0_SA_DQS_DN<3>")
	)
	(segment
		(start 271.977866 -284.277816)
		(end 271.716754 -284.016704)
		(width 0.20066)
		(layer "F.Cu")
		(net "M_C_CPU0_SA_DQS_DN<3>")
	)
	(segment
		(start 274.155408 -284.441646)
		(end 274.14474 -284.430978)
		(width 0.101854)
		(layer "F.Cu")
		(net "M_C_CPU0_SA_DQS_DN<3>")
	)
	(segment
		(start 277.072344 -284.703012)
		(end 276.885654 -284.703012)
		(width 0.20066)
		(layer "F.Cu")
		(net "M_C_CPU0_SA_DQS_DN<3>")
	)
	(segment
		(start 271.716754 -284.016704)
		(end 271.168114 -284.016704)
		(width 0.20066)
		(layer "F.Cu")
		(net "M_C_CPU0_SA_DQS_DN<3>")
	)
	(segment
		(start 279.816814 -284.016704)
		(end 278.711914 -284.016704)
		(width 0.20066)
		(layer "F.Cu")
		(net "M_C_CPU0_SA_DQS_DN<3>")
	)
	(segment
		(start 278.711914 -284.016704)
		(end 278.165306 -284.016704)
		(width 0.20066)
		(layer "F.Cu")
		(net "M_C_CPU0_SA_DQS_DN<3>")
	)
	(segment
		(start 273.667728 -284.703012)
		(end 273.127724 -284.703012)
		(width 0.20066)
		(layer "F.Cu")
		(net "M_C_CPU0_SA_DQS_DN<3>")
	)
	(segment
		(start 276.469094 -284.441646)
		(end 274.155408 -284.441646)
		(width 0.1016)
		(layer "F.Cu")
		(net "M_C_CPU0_SA_DQS_DN<3>")
	)
	(segment
		(start 273.939762 -284.430978)
		(end 273.667728 -284.703012)
		(width 0.20066)
		(layer "F.Cu")
		(net "M_C_CPU0_SA_DQS_DN<3>")
	)
	(segment
		(start 277.904194 -284.277816)
		(end 277.49754 -284.277816)
		(width 0.20066)
		(layer "F.Cu")
		(net "M_C_CPU0_SA_DQS_DN<3>")
	)
	(segment
		(start 273.127724 -284.703012)
		(end 272.491708 -284.277816)
		(width 0.20066)
		(layer "F.Cu")
		(net "M_C_CPU0_SA_DQS_DN<3>")
	)
	(segment
		(start 272.491708 -284.277816)
		(end 271.977866 -284.277816)
		(width 0.20066)
		(layer "F.Cu")
		(net "M_C_CPU0_SA_DQS_DN<3>")
	)
	(segment
		(start 289.540696 -283.919422)
		(end 287.639506 -284.70733)
		(width 0.18288)
		(layer "In6.Cu")
		(net "M_C_CPU0_SA_DQS_DN<3>")
	)
	(segment
		(start 294.432228 -281.29103)
		(end 294.078406 -281.29103)
		(width 0.18288)
		(layer "In6.Cu")
		(net "M_C_CPU0_SA_DQS_DN<3>")
	)
	(segment
		(start 283.445712 -284.690058)
		(end 282.795218 -284.690058)
		(width 0.18288)
		(layer "In6.Cu")
		(net "M_C_CPU0_SA_DQS_DN<3>")
	)
	(segment
		(start 302.864774 -280.102564)
		(end 302.515524 -280.452068)
		(width 0.18288)
		(layer "In6.Cu")
		(net "M_C_CPU0_SA_DQS_DN<3>")
	)
	(segment
		(start 295.182544 -281.041856)
		(end 294.681402 -281.041856)
		(width 0.18288)
		(layer "In6.Cu")
		(net "M_C_CPU0_SA_DQS_DN<3>")
	)
	(segment
		(start 331.990446 -266.858242)
		(end 331.990446 -267.363956)
		(width 0.088646)
		(layer "In6.Cu")
		(net "M_C_CPU0_SA_DQS_DN<3>")
	)
	(segment
		(start 325.712328 -269.380462)
		(end 325.20509 -269.59052)
		(width 0.18288)
		(layer "In6.Cu")
		(net "M_C_CPU0_SA_DQS_DN<3>")
	)
	(segment
		(start 298.78147 -280.191718)
		(end 298.51985 -280.453338)
		(width 0.18288)
		(layer "In6.Cu")
		(net "M_C_CPU0_SA_DQS_DN<3>")
	)
	(segment
		(start 316.2427 -274.935442)
		(end 316.2427 -275.111464)
		(width 0.18288)
		(layer "In6.Cu")
		(net "M_C_CPU0_SA_DQS_DN<3>")
	)
	(segment
		(start 323.387212 -270.478504)
		(end 323.224652 -270.411194)
		(width 0.18288)
		(layer "In6.Cu")
		(net "M_C_CPU0_SA_DQS_DN<3>")
	)
	(segment
		(start 280.07564 -284.27553)
		(end 279.816814 -284.016704)
		(width 0.18288)
		(layer "In6.Cu")
		(net "M_C_CPU0_SA_DQS_DN<3>")
	)
	(segment
		(start 307.853842 -277.160228)
		(end 306.155852 -277.863808)
		(width 0.18288)
		(layer "In6.Cu")
		(net "M_C_CPU0_SA_DQS_DN<3>")
	)
	(segment
		(start 297.042078 -281.088084)
		(end 296.525188 -281.302206)
		(width 0.18288)
		(layer "In6.Cu")
		(net "M_C_CPU0_SA_DQS_DN<3>")
	)
	(segment
		(start 317.758826 -273.595338)
		(end 317.582804 -273.595338)
		(width 0.18288)
		(layer "In6.Cu")
		(net "M_C_CPU0_SA_DQS_DN<3>")
	)
	(segment
		(start 313.130946 -276.723602)
		(end 312.207402 -277.647146)
		(width 0.18288)
		(layer "In6.Cu")
		(net "M_C_CPU0_SA_DQS_DN<3>")
	)
	(segment
		(start 316.630812 -274.54733)
		(end 316.2427 -274.935442)
		(width 0.18288)
		(layer "In6.Cu")
		(net "M_C_CPU0_SA_DQS_DN<3>")
	)
	(segment
		(start 323.961252 -270.105886)
		(end 323.893942 -270.2687)
		(width 0.18288)
		(layer "In6.Cu")
		(net "M_C_CPU0_SA_DQS_DN<3>")
	)
	(segment
		(start 315.023754 -275.803868)
		(end 314.51677 -276.013926)
		(width 0.18288)
		(layer "In6.Cu")
		(net "M_C_CPU0_SA_DQS_DN<3>")
	)
	(segment
		(start 339.212428 -265.632438)
		(end 339.202014 -265.638534)
		(width 0.088646)
		(layer "In6.Cu")
		(net "M_C_CPU0_SA_DQS_DN<3>")
	)
	(segment
		(start 317.582804 -273.595338)
		(end 317.194692 -273.98345)
		(width 0.18288)
		(layer "In6.Cu")
		(net "M_C_CPU0_SA_DQS_DN<3>")
	)
	(segment
		(start 303.534826 -278.484076)
		(end 302.864774 -280.102564)
		(width 0.18288)
		(layer "In6.Cu")
		(net "M_C_CPU0_SA_DQS_DN<3>")
	)
	(segment
		(start 315.693044 -275.66112)
		(end 315.186314 -275.871178)
		(width 0.18288)
		(layer "In6.Cu")
		(net "M_C_CPU0_SA_DQS_DN<3>")
	)
	(segment
		(start 296.525188 -281.302206)
		(end 295.442894 -281.302206)
		(width 0.18288)
		(layer "In6.Cu")
		(net "M_C_CPU0_SA_DQS_DN<3>")
	)
	(segment
		(start 323.224652 -270.411194)
		(end 322.717414 -270.621252)
		(width 0.18288)
		(layer "In6.Cu")
		(net "M_C_CPU0_SA_DQS_DN<3>")
	)
	(segment
		(start 298.51985 -280.453338)
		(end 298.15028 -280.453338)
		(width 0.18288)
		(layer "In6.Cu")
		(net "M_C_CPU0_SA_DQS_DN<3>")
	)
	(segment
		(start 314.51677 -276.013926)
		(end 314.44946 -276.176994)
		(width 0.18288)
		(layer "In6.Cu")
		(net "M_C_CPU0_SA_DQS_DN<3>")
	)
	(segment
		(start 338.272374 -265.632438)
		(end 338.26196 -265.638534)
		(width 0.088646)
		(layer "In6.Cu")
		(net "M_C_CPU0_SA_DQS_DN<3>")
	)
	(segment
		(start 320.736976 -271.441926)
		(end 320.229738 -271.651984)
		(width 0.18288)
		(layer "In6.Cu")
		(net "M_C_CPU0_SA_DQS_DN<3>")
	)
	(segment
		(start 342.021922 -265.638788)
		(end 342.021668 -265.638534)
		(width 0.088646)
		(layer "In6.Cu")
		(net "M_C_CPU0_SA_DQS_DN<3>")
	)
	(segment
		(start 332.905608 -265.94308)
		(end 331.990446 -266.858242)
		(width 0.088646)
		(layer "In6.Cu")
		(net "M_C_CPU0_SA_DQS_DN<3>")
	)
	(segment
		(start 292.902132 -282.18892)
		(end 290.118546 -283.341572)
		(width 0.18288)
		(layer "In6.Cu")
		(net "M_C_CPU0_SA_DQS_DN<3>")
	)
	(segment
		(start 298.15028 -280.453338)
		(end 297.342052 -280.78811)
		(width 0.18288)
		(layer "In6.Cu")
		(net "M_C_CPU0_SA_DQS_DN<3>")
	)
	(segment
		(start 293.602918 -281.488134)
		(end 292.902132 -282.18892)
		(width 0.18288)
		(layer "In6.Cu")
		(net "M_C_CPU0_SA_DQS_DN<3>")
	)
	(segment
		(start 312.207402 -277.647146)
		(end 311.71007 -277.647146)
		(width 0.18288)
		(layer "In6.Cu")
		(net "M_C_CPU0_SA_DQS_DN<3>")
	)
	(segment
		(start 333.445866 -265.72845)
		(end 333.231236 -265.94308)
		(width 0.088646)
		(layer "In6.Cu")
		(net "M_C_CPU0_SA_DQS_DN<3>")
	)
	(segment
		(start 299.282612 -280.191718)
		(end 298.78147 -280.191718)
		(width 0.18288)
		(layer "In6.Cu")
		(net "M_C_CPU0_SA_DQS_DN<3>")
	)
	(segment
		(start 316.806834 -274.54733)
		(end 316.630812 -274.54733)
		(width 0.18288)
		(layer "In6.Cu")
		(net "M_C_CPU0_SA_DQS_DN<3>")
	)
	(segment
		(start 323.893942 -270.2687)
		(end 323.387212 -270.478504)
		(width 0.18288)
		(layer "In6.Cu")
		(net "M_C_CPU0_SA_DQS_DN<3>")
	)
	(segment
		(start 314.44946 -276.176994)
		(end 313.130946 -276.723602)
		(width 0.18288)
		(layer "In6.Cu")
		(net "M_C_CPU0_SA_DQS_DN<3>")
	)
	(segment
		(start 294.681402 -281.041856)
		(end 294.432228 -281.29103)
		(width 0.18288)
		(layer "In6.Cu")
		(net "M_C_CPU0_SA_DQS_DN<3>")
	)
	(segment
		(start 321.473576 -271.136618)
		(end 321.406266 -271.299432)
		(width 0.18288)
		(layer "In6.Cu")
		(net "M_C_CPU0_SA_DQS_DN<3>")
	)
	(segment
		(start 321.406266 -271.299432)
		(end 320.899536 -271.509236)
		(width 0.18288)
		(layer "In6.Cu")
		(net "M_C_CPU0_SA_DQS_DN<3>")
	)
	(segment
		(start 317.194692 -273.98345)
		(end 317.194692 -274.159472)
		(width 0.18288)
		(layer "In6.Cu")
		(net "M_C_CPU0_SA_DQS_DN<3>")
	)
	(segment
		(start 318.534796 -272.643346)
		(end 318.146684 -273.031458)
		(width 0.18288)
		(layer "In6.Cu")
		(net "M_C_CPU0_SA_DQS_DN<3>")
	)
	(segment
		(start 333.231236 -265.94308)
		(end 332.905608 -265.94308)
		(width 0.088646)
		(layer "In6.Cu")
		(net "M_C_CPU0_SA_DQS_DN<3>")
	)
	(segment
		(start 325.20509 -269.59052)
		(end 325.13778 -269.753334)
		(width 0.18288)
		(layer "In6.Cu")
		(net "M_C_CPU0_SA_DQS_DN<3>")
	)
	(segment
		(start 330.2127 -267.650976)
		(end 325.874888 -269.447772)
		(width 0.18288)
		(layer "In6.Cu")
		(net "M_C_CPU0_SA_DQS_DN<3>")
	)
	(segment
		(start 331.00264 -267.650976)
		(end 330.979272 -267.650976)
		(width 0.088646)
		(layer "In6.Cu")
		(net "M_C_CPU0_SA_DQS_DN<3>")
	)
	(segment
		(start 319.098676 -272.255488)
		(end 318.710818 -272.643346)
		(width 0.18288)
		(layer "In6.Cu")
		(net "M_C_CPU0_SA_DQS_DN<3>")
	)
	(segment
		(start 320.229738 -271.651984)
		(end 320.162428 -271.814798)
		(width 0.18288)
		(layer "In6.Cu")
		(net "M_C_CPU0_SA_DQS_DN<3>")
	)
	(segment
		(start 330.979272 -267.650976)
		(end 330.2127 -267.650976)
		(width 0.18288)
		(layer "In6.Cu")
		(net "M_C_CPU0_SA_DQS_DN<3>")
	)
	(segment
		(start 280.528522 -284.27553)
		(end 280.07564 -284.27553)
		(width 0.18288)
		(layer "In6.Cu")
		(net "M_C_CPU0_SA_DQS_DN<3>")
	)
	(segment
		(start 283.694124 -284.441646)
		(end 283.445712 -284.690058)
		(width 0.18288)
		(layer "In6.Cu")
		(net "M_C_CPU0_SA_DQS_DN<3>")
	)
	(segment
		(start 284.460442 -284.70733)
		(end 284.194758 -284.441646)
		(width 0.18288)
		(layer "In6.Cu")
		(net "M_C_CPU0_SA_DQS_DN<3>")
	)
	(segment
		(start 325.13778 -269.753334)
		(end 324.63105 -269.963138)
		(width 0.18288)
		(layer "In6.Cu")
		(net "M_C_CPU0_SA_DQS_DN<3>")
	)
	(segment
		(start 318.146684 -273.031458)
		(end 318.146684 -273.20748)
		(width 0.18288)
		(layer "In6.Cu")
		(net "M_C_CPU0_SA_DQS_DN<3>")
	)
	(segment
		(start 320.162428 -271.814798)
		(end 319.098676 -272.255488)
		(width 0.18288)
		(layer "In6.Cu")
		(net "M_C_CPU0_SA_DQS_DN<3>")
	)
	(segment
		(start 322.143374 -270.99387)
		(end 321.980814 -270.92656)
		(width 0.18288)
		(layer "In6.Cu")
		(net "M_C_CPU0_SA_DQS_DN<3>")
	)
	(segment
		(start 331.643736 -267.710666)
		(end 331.06233 -267.710666)
		(width 0.088646)
		(layer "In6.Cu")
		(net "M_C_CPU0_SA_DQS_DN<3>")
	)
	(segment
		(start 318.710818 -272.643346)
		(end 318.534796 -272.643346)
		(width 0.18288)
		(layer "In6.Cu")
		(net "M_C_CPU0_SA_DQS_DN<3>")
	)
	(segment
		(start 297.342052 -280.78811)
		(end 297.042078 -281.088084)
		(width 0.18288)
		(layer "In6.Cu")
		(net "M_C_CPU0_SA_DQS_DN<3>")
	)
	(segment
		(start 315.186314 -275.871178)
		(end 315.023754 -275.803868)
		(width 0.18288)
		(layer "In6.Cu")
		(net "M_C_CPU0_SA_DQS_DN<3>")
	)
	(segment
		(start 281.810968 -284.073346)
		(end 281.01671 -284.073346)
		(width 0.18288)
		(layer "In6.Cu")
		(net "M_C_CPU0_SA_DQS_DN<3>")
	)
	(segment
		(start 342.27516 -265.492992)
		(end 342.021922 -265.638788)
		(width 0.088646)
		(layer "In6.Cu")
		(net "M_C_CPU0_SA_DQS_DN<3>")
	)
	(segment
		(start 311.71007 -277.647146)
		(end 310.533542 -277.160228)
		(width 0.18288)
		(layer "In6.Cu")
		(net "M_C_CPU0_SA_DQS_DN<3>")
	)
	(segment
		(start 341.096346 -265.629898)
		(end 341.081614 -265.638534)
		(width 0.088646)
		(layer "In6.Cu")
		(net "M_C_CPU0_SA_DQS_DN<3>")
	)
	(segment
		(start 284.194758 -284.441646)
		(end 283.694124 -284.441646)
		(width 0.18288)
		(layer "In6.Cu")
		(net "M_C_CPU0_SA_DQS_DN<3>")
	)
	(segment
		(start 331.990446 -267.363956)
		(end 331.643736 -267.710666)
		(width 0.088646)
		(layer "In6.Cu")
		(net "M_C_CPU0_SA_DQS_DN<3>")
	)
	(segment
		(start 294.078406 -281.29103)
		(end 293.602918 -281.488134)
		(width 0.18288)
		(layer "In6.Cu")
		(net "M_C_CPU0_SA_DQS_DN<3>")
	)
	(segment
		(start 295.442894 -281.302206)
		(end 295.182544 -281.041856)
		(width 0.18288)
		(layer "In6.Cu")
		(net "M_C_CPU0_SA_DQS_DN<3>")
	)
	(segment
		(start 322.650104 -270.784066)
		(end 322.143374 -270.99387)
		(width 0.18288)
		(layer "In6.Cu")
		(net "M_C_CPU0_SA_DQS_DN<3>")
	)
	(segment
		(start 320.899536 -271.509236)
		(end 320.736976 -271.441926)
		(width 0.18288)
		(layer "In6.Cu")
		(net "M_C_CPU0_SA_DQS_DN<3>")
	)
	(segment
		(start 310.533542 -277.160228)
		(end 307.853842 -277.160228)
		(width 0.18288)
		(layer "In6.Cu")
		(net "M_C_CPU0_SA_DQS_DN<3>")
	)
	(segment
		(start 321.980814 -270.92656)
		(end 321.473576 -271.136618)
		(width 0.18288)
		(layer "In6.Cu")
		(net "M_C_CPU0_SA_DQS_DN<3>")
	)
	(segment
		(start 325.874888 -269.447772)
		(end 325.712328 -269.380462)
		(width 0.18288)
		(layer "In6.Cu")
		(net "M_C_CPU0_SA_DQS_DN<3>")
	)
	(segment
		(start 342.774016 -265.314176)
		(end 342.742266 -265.43)
		(width 0.088646)
		(layer "In6.Cu")
		(net "M_C_CPU0_SA_DQS_DN<3>")
	)
	(segment
		(start 324.63105 -269.963138)
		(end 324.46849 -269.895828)
		(width 0.18288)
		(layer "In6.Cu")
		(net "M_C_CPU0_SA_DQS_DN<3>")
	)
	(segment
		(start 317.194692 -274.159472)
		(end 316.806834 -274.54733)
		(width 0.18288)
		(layer "In6.Cu")
		(net "M_C_CPU0_SA_DQS_DN<3>")
	)
	(segment
		(start 290.118546 -283.341572)
		(end 289.540696 -283.919422)
		(width 0.18288)
		(layer "In6.Cu")
		(net "M_C_CPU0_SA_DQS_DN<3>")
	)
	(segment
		(start 331.06233 -267.710666)
		(end 331.00264 -267.650976)
		(width 0.088646)
		(layer "In6.Cu")
		(net "M_C_CPU0_SA_DQS_DN<3>")
	)
	(segment
		(start 342.742266 -265.43)
		(end 342.703404 -265.452098)
		(width 0.088646)
		(layer "In6.Cu")
		(net "M_C_CPU0_SA_DQS_DN<3>")
	)
	(segment
		(start 324.46849 -269.895828)
		(end 323.961252 -270.105886)
		(width 0.18288)
		(layer "In6.Cu")
		(net "M_C_CPU0_SA_DQS_DN<3>")
	)
	(segment
		(start 282.437586 -284.332934)
		(end 281.810968 -284.073346)
		(width 0.18288)
		(layer "In6.Cu")
		(net "M_C_CPU0_SA_DQS_DN<3>")
	)
	(segment
		(start 281.01671 -284.073346)
		(end 280.528522 -284.27553)
		(width 0.18288)
		(layer "In6.Cu")
		(net "M_C_CPU0_SA_DQS_DN<3>")
	)
	(segment
		(start 342.548718 -265.492992)
		(end 342.27516 -265.492992)
		(width 0.088646)
		(layer "In6.Cu")
		(net "M_C_CPU0_SA_DQS_DN<3>")
	)
	(segment
		(start 282.795218 -284.690058)
		(end 282.437586 -284.332934)
		(width 0.18288)
		(layer "In6.Cu")
		(net "M_C_CPU0_SA_DQS_DN<3>")
	)
	(segment
		(start 304.155094 -277.863808)
		(end 303.534826 -278.484076)
		(width 0.18288)
		(layer "In6.Cu")
		(net "M_C_CPU0_SA_DQS_DN<3>")
	)
	(segment
		(start 340.151974 -265.632438)
		(end 340.14156 -265.638534)
		(width 0.088646)
		(layer "In6.Cu")
		(net "M_C_CPU0_SA_DQS_DN<3>")
	)
	(segment
		(start 306.155852 -277.863808)
		(end 304.155094 -277.863808)
		(width 0.18288)
		(layer "In6.Cu")
		(net "M_C_CPU0_SA_DQS_DN<3>")
	)
	(segment
		(start 322.717414 -270.621252)
		(end 322.650104 -270.784066)
		(width 0.18288)
		(layer "In6.Cu")
		(net "M_C_CPU0_SA_DQS_DN<3>")
	)
	(segment
		(start 287.639506 -284.70733)
		(end 284.460442 -284.70733)
		(width 0.18288)
		(layer "In6.Cu")
		(net "M_C_CPU0_SA_DQS_DN<3>")
	)
	(segment
		(start 316.2427 -275.111464)
		(end 315.693044 -275.66112)
		(width 0.18288)
		(layer "In6.Cu")
		(net "M_C_CPU0_SA_DQS_DN<3>")
	)
	(segment
		(start 341.647272 -265.638534)
		(end 341.647018 -265.638534)
		(width 0.088646)
		(layer "In6.Cu")
		(net "M_C_CPU0_SA_DQS_DN<3>")
	)
	(segment
		(start 302.515524 -280.452068)
		(end 299.542962 -280.452068)
		(width 0.18288)
		(layer "In6.Cu")
		(net "M_C_CPU0_SA_DQS_DN<3>")
	)
	(segment
		(start 318.146684 -273.20748)
		(end 317.758826 -273.595338)
		(width 0.18288)
		(layer "In6.Cu")
		(net "M_C_CPU0_SA_DQS_DN<3>")
	)
	(segment
		(start 299.542962 -280.452068)
		(end 299.282612 -280.191718)
		(width 0.18288)
		(layer "In6.Cu")
		(net "M_C_CPU0_SA_DQS_DN<3>")
	)
	(arc
		(start 337.32216 -265.638534)
		(mid 337.134962 -265.688677)
		(end 336.947764 -265.638534)
		(width 0.088646)
		(layer "In6.Cu")
		(net "M_C_CPU0_SA_DQS_DN<3>")
	)
	(arc
		(start 337.887564 -265.638534)
		(mid 337.604862 -265.562758)
		(end 337.32216 -265.638534)
		(width 0.088646)
		(layer "In6.Cu")
		(net "M_C_CPU0_SA_DQS_DN<3>")
	)
	(arc
		(start 338.827618 -265.638534)
		(mid 338.550805 -265.562664)
		(end 338.272374 -265.632438)
		(width 0.088646)
		(layer "In6.Cu")
		(net "M_C_CPU0_SA_DQS_DN<3>")
	)
	(arc
		(start 342.703404 -265.452098)
		(mid 342.628719 -265.482603)
		(end 342.548718 -265.492992)
		(width 0.088646)
		(layer "In6.Cu")
		(net "M_C_CPU0_SA_DQS_DN<3>")
	)
	(arc
		(start 335.44256 -265.638534)
		(mid 335.255362 -265.688677)
		(end 335.068164 -265.638534)
		(width 0.088646)
		(layer "In6.Cu")
		(net "M_C_CPU0_SA_DQS_DN<3>")
	)
	(arc
		(start 339.202014 -265.638534)
		(mid 339.014816 -265.688677)
		(end 338.827618 -265.638534)
		(width 0.088646)
		(layer "In6.Cu")
		(net "M_C_CPU0_SA_DQS_DN<3>")
	)
	(arc
		(start 338.26196 -265.638534)
		(mid 338.074762 -265.688677)
		(end 337.887564 -265.638534)
		(width 0.088646)
		(layer "In6.Cu")
		(net "M_C_CPU0_SA_DQS_DN<3>")
	)
	(arc
		(start 342.021668 -265.638534)
		(mid 341.83447 -265.688677)
		(end 341.647272 -265.638534)
		(width 0.088646)
		(layer "In6.Cu")
		(net "M_C_CPU0_SA_DQS_DN<3>")
	)
	(arc
		(start 340.707218 -265.638534)
		(mid 340.430405 -265.562664)
		(end 340.151974 -265.632438)
		(width 0.088646)
		(layer "In6.Cu")
		(net "M_C_CPU0_SA_DQS_DN<3>")
	)
	(arc
		(start 339.767164 -265.638534)
		(mid 339.490605 -265.562791)
		(end 339.212428 -265.632438)
		(width 0.088646)
		(layer "In6.Cu")
		(net "M_C_CPU0_SA_DQS_DN<3>")
	)
	(arc
		(start 341.647018 -265.638534)
		(mid 341.372789 -265.562609)
		(end 341.096346 -265.629898)
		(width 0.088646)
		(layer "In6.Cu")
		(net "M_C_CPU0_SA_DQS_DN<3>")
	)
	(arc
		(start 334.50276 -265.638534)
		(mid 334.315562 -265.688677)
		(end 334.128364 -265.638534)
		(width 0.088646)
		(layer "In6.Cu")
		(net "M_C_CPU0_SA_DQS_DN<3>")
	)
	(arc
		(start 340.14156 -265.638534)
		(mid 339.954362 -265.688677)
		(end 339.767164 -265.638534)
		(width 0.088646)
		(layer "In6.Cu")
		(net "M_C_CPU0_SA_DQS_DN<3>")
	)
	(arc
		(start 341.081614 -265.638534)
		(mid 340.894416 -265.688677)
		(end 340.707218 -265.638534)
		(width 0.088646)
		(layer "In6.Cu")
		(net "M_C_CPU0_SA_DQS_DN<3>")
	)
	(arc
		(start 334.128364 -265.638534)
		(mid 333.771841 -265.567631)
		(end 333.445866 -265.72845)
		(width 0.088646)
		(layer "In6.Cu")
		(net "M_C_CPU0_SA_DQS_DN<3>")
	)
	(arc
		(start 336.38236 -265.638534)
		(mid 336.195162 -265.688677)
		(end 336.007964 -265.638534)
		(width 0.088646)
		(layer "In6.Cu")
		(net "M_C_CPU0_SA_DQS_DN<3>")
	)
	(arc
		(start 335.068164 -265.638534)
		(mid 334.785462 -265.562792)
		(end 334.50276 -265.638534)
		(width 0.088646)
		(layer "In6.Cu")
		(net "M_C_CPU0_SA_DQS_DN<3>")
	)
	(arc
		(start 336.947764 -265.638534)
		(mid 336.665062 -265.562758)
		(end 336.38236 -265.638534)
		(width 0.088646)
		(layer "In6.Cu")
		(net "M_C_CPU0_SA_DQS_DN<3>")
	)
	(arc
		(start 336.007964 -265.638534)
		(mid 335.725262 -265.562792)
		(end 335.44256 -265.638534)
		(width 0.088646)
		(layer "In6.Cu")
		(net "M_C_CPU0_SA_DQS_DN<3>")
	)
	(segment
		(start 276.469094 -293.79164)
		(end 274.155408 -293.79164)
		(width 0.1016)
		(layer "F.Cu")
		(net "M_C_CPU0_SA_DQS_DN<2>")
	)
	(segment
		(start 272.491708 -293.62781)
		(end 271.977866 -293.62781)
		(width 0.20066)
		(layer "F.Cu")
		(net "M_C_CPU0_SA_DQS_DN<2>")
	)
	(segment
		(start 277.49754 -293.62781)
		(end 277.072344 -294.053006)
		(width 0.20066)
		(layer "F.Cu")
		(net "M_C_CPU0_SA_DQS_DN<2>")
	)
	(segment
		(start 278.165306 -293.366698)
		(end 277.904194 -293.62781)
		(width 0.20066)
		(layer "F.Cu")
		(net "M_C_CPU0_SA_DQS_DN<2>")
	)
	(segment
		(start 271.716754 -293.366698)
		(end 271.168114 -293.366698)
		(width 0.20066)
		(layer "F.Cu")
		(net "M_C_CPU0_SA_DQS_DN<2>")
	)
	(segment
		(start 277.072344 -294.053006)
		(end 276.885654 -294.053006)
		(width 0.20066)
		(layer "F.Cu")
		(net "M_C_CPU0_SA_DQS_DN<2>")
	)
	(segment
		(start 274.14474 -293.780972)
		(end 274.143978 -293.780972)
		(width 0.101854)
		(layer "F.Cu")
		(net "M_C_CPU0_SA_DQS_DN<2>")
	)
	(segment
		(start 277.904194 -293.62781)
		(end 277.49754 -293.62781)
		(width 0.20066)
		(layer "F.Cu")
		(net "M_C_CPU0_SA_DQS_DN<2>")
	)
	(segment
		(start 273.127724 -294.053006)
		(end 272.491708 -293.62781)
		(width 0.20066)
		(layer "F.Cu")
		(net "M_C_CPU0_SA_DQS_DN<2>")
	)
	(segment
		(start 279.816814 -293.366698)
		(end 278.711914 -293.366698)
		(width 0.20066)
		(layer "F.Cu")
		(net "M_C_CPU0_SA_DQS_DN<2>")
	)
	(segment
		(start 276.885654 -294.053006)
		(end 276.624288 -293.79164)
		(width 0.20066)
		(layer "F.Cu")
		(net "M_C_CPU0_SA_DQS_DN<2>")
	)
	(segment
		(start 274.155408 -293.79164)
		(end 274.14474 -293.780972)
		(width 0.101854)
		(layer "F.Cu")
		(net "M_C_CPU0_SA_DQS_DN<2>")
	)
	(segment
		(start 274.143978 -293.780972)
		(end 273.939762 -293.780972)
		(width 0.20066)
		(layer "F.Cu")
		(net "M_C_CPU0_SA_DQS_DN<2>")
	)
	(segment
		(start 339.484716 -267.219938)
		(end 339.484462 -267.755878)
		(width 0.20066)
		(layer "F.Cu")
		(net "M_C_CPU0_SA_DQS_DN<2>")
	)
	(segment
		(start 276.624288 -293.79164)
		(end 276.469094 -293.79164)
		(width 0.20066)
		(layer "F.Cu")
		(net "M_C_CPU0_SA_DQS_DN<2>")
	)
	(segment
		(start 273.667728 -294.053006)
		(end 273.127724 -294.053006)
		(width 0.20066)
		(layer "F.Cu")
		(net "M_C_CPU0_SA_DQS_DN<2>")
	)
	(segment
		(start 278.711914 -293.366698)
		(end 278.165306 -293.366698)
		(width 0.20066)
		(layer "F.Cu")
		(net "M_C_CPU0_SA_DQS_DN<2>")
	)
	(segment
		(start 273.939762 -293.780972)
		(end 273.667728 -294.053006)
		(width 0.20066)
		(layer "F.Cu")
		(net "M_C_CPU0_SA_DQS_DN<2>")
	)
	(segment
		(start 271.977866 -293.62781)
		(end 271.716754 -293.366698)
		(width 0.20066)
		(layer "F.Cu")
		(net "M_C_CPU0_SA_DQS_DN<2>")
	)
	(segment
		(start 325.626476 -273.834098)
		(end 325.626476 -274.01012)
		(width 0.18288)
		(layer "In4.Cu")
		(net "M_C_CPU0_SA_DQS_DN<2>")
	)
	(segment
		(start 307.352446 -291.890958)
		(end 304.759868 -292.965378)
		(width 0.18288)
		(layer "In4.Cu")
		(net "M_C_CPU0_SA_DQS_DN<2>")
	)
	(segment
		(start 326.578468 -272.882106)
		(end 326.578468 -273.058128)
		(width 0.18288)
		(layer "In4.Cu")
		(net "M_C_CPU0_SA_DQS_DN<2>")
	)
	(segment
		(start 325.238618 -274.397978)
		(end 325.062596 -274.397978)
		(width 0.18288)
		(layer "In4.Cu")
		(net "M_C_CPU0_SA_DQS_DN<2>")
	)
	(segment
		(start 280.734262 -293.6367)
		(end 280.086816 -293.6367)
		(width 0.18288)
		(layer "In4.Cu")
		(net "M_C_CPU0_SA_DQS_DN<2>")
	)
	(segment
		(start 295.11371 -294.641778)
		(end 294.70858 -294.641778)
		(width 0.18288)
		(layer "In4.Cu")
		(net "M_C_CPU0_SA_DQS_DN<2>")
	)
	(segment
		(start 313.511946 -288.62274)
		(end 313.149488 -288.772854)
		(width 0.18288)
		(layer "In4.Cu")
		(net "M_C_CPU0_SA_DQS_DN<2>")
	)
	(segment
		(start 323.334634 -276.301962)
		(end 323.158612 -276.301962)
		(width 0.18288)
		(layer "In4.Cu")
		(net "M_C_CPU0_SA_DQS_DN<2>")
	)
	(segment
		(start 336.857086 -268.077696)
		(end 336.846672 -268.083538)
		(width 0.088646)
		(layer "In4.Cu")
		(net "M_C_CPU0_SA_DQS_DN<2>")
	)
	(segment
		(start 280.992072 -293.37889)
		(end 280.734262 -293.6367)
		(width 0.18288)
		(layer "In4.Cu")
		(net "M_C_CPU0_SA_DQS_DN<2>")
	)
	(segment
		(start 338.357718 -268.080236)
		(end 338.357464 -268.080236)
		(width 0.088646)
		(layer "In4.Cu")
		(net "M_C_CPU0_SA_DQS_DN<2>")
	)
	(segment
		(start 284.182566 -293.79164)
		(end 283.725112 -293.79164)
		(width 0.18288)
		(layer "In4.Cu")
		(net "M_C_CPU0_SA_DQS_DN<2>")
	)
	(segment
		(start 313.149488 -288.772854)
		(end 311.921906 -289.017202)
		(width 0.18288)
		(layer "In4.Cu")
		(net "M_C_CPU0_SA_DQS_DN<2>")
	)
	(segment
		(start 283.447744 -294.069008)
		(end 282.949904 -294.069008)
		(width 0.18288)
		(layer "In4.Cu")
		(net "M_C_CPU0_SA_DQS_DN<2>")
	)
	(segment
		(start 329.434444 -270.202152)
		(end 329.046586 -270.59001)
		(width 0.18288)
		(layer "In4.Cu")
		(net "M_C_CPU0_SA_DQS_DN<2>")
	)
	(segment
		(start 280.086816 -293.6367)
		(end 279.816814 -293.366698)
		(width 0.18288)
		(layer "In4.Cu")
		(net "M_C_CPU0_SA_DQS_DN<2>")
	)
	(segment
		(start 329.434444 -270.02613)
		(end 329.434444 -270.202152)
		(width 0.18288)
		(layer "In4.Cu")
		(net "M_C_CPU0_SA_DQS_DN<2>")
	)
	(segment
		(start 329.998578 -269.638018)
		(end 329.822556 -269.638018)
		(width 0.18288)
		(layer "In4.Cu")
		(net "M_C_CPU0_SA_DQS_DN<2>")
	)
	(segment
		(start 339.452712 -267.871702)
		(end 339.41385 -267.8938)
		(width 0.088646)
		(layer "In4.Cu")
		(net "M_C_CPU0_SA_DQS_DN<2>")
	)
	(segment
		(start 331.258672 -269.31366)
		(end 330.322936 -269.31366)
		(width 0.18288)
		(layer "In4.Cu")
		(net "M_C_CPU0_SA_DQS_DN<2>")
	)
	(segment
		(start 282.259786 -293.37889)
		(end 280.992072 -293.37889)
		(width 0.18288)
		(layer "In4.Cu")
		(net "M_C_CPU0_SA_DQS_DN<2>")
	)
	(segment
		(start 331.559916 -269.37335)
		(end 331.34173 -269.37335)
		(width 0.088646)
		(layer "In4.Cu")
		(net "M_C_CPU0_SA_DQS_DN<2>")
	)
	(segment
		(start 295.998392 -294.643302)
		(end 295.726104 -294.91559)
		(width 0.18288)
		(layer "In4.Cu")
		(net "M_C_CPU0_SA_DQS_DN<2>")
	)
	(segment
		(start 298.809664 -293.791894)
		(end 298.541186 -294.060372)
		(width 0.18288)
		(layer "In4.Cu")
		(net "M_C_CPU0_SA_DQS_DN<2>")
	)
	(segment
		(start 324.674484 -274.78609)
		(end 324.674484 -274.962112)
		(width 0.18288)
		(layer "In4.Cu")
		(net "M_C_CPU0_SA_DQS_DN<2>")
	)
	(segment
		(start 323.158612 -276.301962)
		(end 322.7705 -276.690074)
		(width 0.18288)
		(layer "In4.Cu")
		(net "M_C_CPU0_SA_DQS_DN<2>")
	)
	(segment
		(start 314.302902 -287.828228)
		(end 313.907678 -287.828228)
		(width 0.18288)
		(layer "In4.Cu")
		(net "M_C_CPU0_SA_DQS_DN<2>")
	)
	(segment
		(start 317.581026 -284.550358)
		(end 314.302902 -287.828228)
		(width 0.18288)
		(layer "In4.Cu")
		(net "M_C_CPU0_SA_DQS_DN<2>")
	)
	(segment
		(start 282.949904 -294.069008)
		(end 282.259786 -293.37889)
		(width 0.18288)
		(layer "In4.Cu")
		(net "M_C_CPU0_SA_DQS_DN<2>")
	)
	(segment
		(start 332.745334 -268.400276)
		(end 332.38186 -268.551152)
		(width 0.088646)
		(layer "In4.Cu")
		(net "M_C_CPU0_SA_DQS_DN<2>")
	)
	(segment
		(start 313.652154 -288.083752)
		(end 313.652154 -288.482786)
		(width 0.18288)
		(layer "In4.Cu")
		(net "M_C_CPU0_SA_DQS_DN<2>")
	)
	(segment
		(start 332.38186 -268.551152)
		(end 331.559916 -269.37335)
		(width 0.088646)
		(layer "In4.Cu")
		(net "M_C_CPU0_SA_DQS_DN<2>")
	)
	(segment
		(start 294.70858 -294.641778)
		(end 294.443912 -294.906446)
		(width 0.18288)
		(layer "In4.Cu")
		(net "M_C_CPU0_SA_DQS_DN<2>")
	)
	(segment
		(start 295.387522 -294.91559)
		(end 295.11371 -294.641778)
		(width 0.18288)
		(layer "In4.Cu")
		(net "M_C_CPU0_SA_DQS_DN<2>")
	)
	(segment
		(start 339.484462 -267.755878)
		(end 339.452712 -267.871702)
		(width 0.088646)
		(layer "In4.Cu")
		(net "M_C_CPU0_SA_DQS_DN<2>")
	)
	(segment
		(start 283.725112 -293.79164)
		(end 283.447744 -294.069008)
		(width 0.18288)
		(layer "In4.Cu")
		(net "M_C_CPU0_SA_DQS_DN<2>")
	)
	(segment
		(start 298.117514 -294.060372)
		(end 296.712894 -294.643302)
		(width 0.18288)
		(layer "In4.Cu")
		(net "M_C_CPU0_SA_DQS_DN<2>")
	)
	(segment
		(start 325.062596 -274.397978)
		(end 324.674484 -274.78609)
		(width 0.18288)
		(layer "In4.Cu")
		(net "M_C_CPU0_SA_DQS_DN<2>")
	)
	(segment
		(start 313.907678 -287.828228)
		(end 313.652154 -288.083752)
		(width 0.18288)
		(layer "In4.Cu")
		(net "M_C_CPU0_SA_DQS_DN<2>")
	)
	(segment
		(start 309.027322 -290.21659)
		(end 307.352446 -291.890958)
		(width 0.18288)
		(layer "In4.Cu")
		(net "M_C_CPU0_SA_DQS_DN<2>")
	)
	(segment
		(start 326.578468 -273.058128)
		(end 326.19061 -273.445986)
		(width 0.18288)
		(layer "In4.Cu")
		(net "M_C_CPU0_SA_DQS_DN<2>")
	)
	(segment
		(start 293.938452 -294.906446)
		(end 292.41877 -293.386764)
		(width 0.18288)
		(layer "In4.Cu")
		(net "M_C_CPU0_SA_DQS_DN<2>")
	)
	(segment
		(start 327.142602 -272.493994)
		(end 326.96658 -272.493994)
		(width 0.18288)
		(layer "In4.Cu")
		(net "M_C_CPU0_SA_DQS_DN<2>")
	)
	(segment
		(start 331.34173 -269.37335)
		(end 331.28204 -269.31366)
		(width 0.088646)
		(layer "In4.Cu")
		(net "M_C_CPU0_SA_DQS_DN<2>")
	)
	(segment
		(start 326.19061 -273.445986)
		(end 326.014588 -273.445986)
		(width 0.18288)
		(layer "In4.Cu")
		(net "M_C_CPU0_SA_DQS_DN<2>")
	)
	(segment
		(start 284.454092 -294.063166)
		(end 284.182566 -293.79164)
		(width 0.18288)
		(layer "In4.Cu")
		(net "M_C_CPU0_SA_DQS_DN<2>")
	)
	(segment
		(start 322.7705 -276.690074)
		(end 322.7705 -276.866096)
		(width 0.18288)
		(layer "In4.Cu")
		(net "M_C_CPU0_SA_DQS_DN<2>")
	)
	(segment
		(start 289.007296 -293.386764)
		(end 287.3756 -294.063166)
		(width 0.18288)
		(layer "In4.Cu")
		(net "M_C_CPU0_SA_DQS_DN<2>")
	)
	(segment
		(start 339.259164 -267.934694)
		(end 338.985606 -267.934694)
		(width 0.088646)
		(layer "In4.Cu")
		(net "M_C_CPU0_SA_DQS_DN<2>")
	)
	(segment
		(start 330.322936 -269.31366)
		(end 329.998578 -269.638018)
		(width 0.18288)
		(layer "In4.Cu")
		(net "M_C_CPU0_SA_DQS_DN<2>")
	)
	(segment
		(start 298.541186 -294.060372)
		(end 298.117514 -294.060372)
		(width 0.18288)
		(layer "In4.Cu")
		(net "M_C_CPU0_SA_DQS_DN<2>")
	)
	(segment
		(start 338.732368 -268.08049)
		(end 338.732114 -268.080236)
		(width 0.088646)
		(layer "In4.Cu")
		(net "M_C_CPU0_SA_DQS_DN<2>")
	)
	(segment
		(start 287.3756 -294.063166)
		(end 284.454092 -294.063166)
		(width 0.18288)
		(layer "In4.Cu")
		(net "M_C_CPU0_SA_DQS_DN<2>")
	)
	(segment
		(start 327.53046 -272.106136)
		(end 327.142602 -272.493994)
		(width 0.18288)
		(layer "In4.Cu")
		(net "M_C_CPU0_SA_DQS_DN<2>")
	)
	(segment
		(start 328.870564 -270.59001)
		(end 328.482452 -270.978122)
		(width 0.18288)
		(layer "In4.Cu")
		(net "M_C_CPU0_SA_DQS_DN<2>")
	)
	(segment
		(start 331.28204 -269.31366)
		(end 331.258672 -269.31366)
		(width 0.088646)
		(layer "In4.Cu")
		(net "M_C_CPU0_SA_DQS_DN<2>")
	)
	(segment
		(start 324.110604 -275.34997)
		(end 323.722492 -275.738082)
		(width 0.18288)
		(layer "In4.Cu")
		(net "M_C_CPU0_SA_DQS_DN<2>")
	)
	(segment
		(start 311.921906 -289.017202)
		(end 309.027322 -290.21659)
		(width 0.18288)
		(layer "In4.Cu")
		(net "M_C_CPU0_SA_DQS_DN<2>")
	)
	(segment
		(start 296.712894 -294.643302)
		(end 295.998392 -294.643302)
		(width 0.18288)
		(layer "In4.Cu")
		(net "M_C_CPU0_SA_DQS_DN<2>")
	)
	(segment
		(start 323.722492 -275.738082)
		(end 323.722492 -275.914104)
		(width 0.18288)
		(layer "In4.Cu")
		(net "M_C_CPU0_SA_DQS_DN<2>")
	)
	(segment
		(start 328.482452 -270.978122)
		(end 328.482452 -271.154144)
		(width 0.18288)
		(layer "In4.Cu")
		(net "M_C_CPU0_SA_DQS_DN<2>")
	)
	(segment
		(start 326.014588 -273.445986)
		(end 325.626476 -273.834098)
		(width 0.18288)
		(layer "In4.Cu")
		(net "M_C_CPU0_SA_DQS_DN<2>")
	)
	(segment
		(start 295.726104 -294.91559)
		(end 295.387522 -294.91559)
		(width 0.18288)
		(layer "In4.Cu")
		(net "M_C_CPU0_SA_DQS_DN<2>")
	)
	(segment
		(start 323.722492 -275.914104)
		(end 323.334634 -276.301962)
		(width 0.18288)
		(layer "In4.Cu")
		(net "M_C_CPU0_SA_DQS_DN<2>")
	)
	(segment
		(start 299.502576 -294.076628)
		(end 299.217842 -293.791894)
		(width 0.18288)
		(layer "In4.Cu")
		(net "M_C_CPU0_SA_DQS_DN<2>")
	)
	(segment
		(start 327.918572 -271.542002)
		(end 327.53046 -271.930114)
		(width 0.18288)
		(layer "In4.Cu")
		(net "M_C_CPU0_SA_DQS_DN<2>")
	)
	(segment
		(start 329.822556 -269.638018)
		(end 329.434444 -270.02613)
		(width 0.18288)
		(layer "In4.Cu")
		(net "M_C_CPU0_SA_DQS_DN<2>")
	)
	(segment
		(start 301.26813 -292.965378)
		(end 300.15688 -294.076628)
		(width 0.18288)
		(layer "In4.Cu")
		(net "M_C_CPU0_SA_DQS_DN<2>")
	)
	(segment
		(start 328.094594 -271.542002)
		(end 327.918572 -271.542002)
		(width 0.18288)
		(layer "In4.Cu")
		(net "M_C_CPU0_SA_DQS_DN<2>")
	)
	(segment
		(start 337.79587 -268.078204)
		(end 337.792314 -268.080236)
		(width 0.088646)
		(layer "In4.Cu")
		(net "M_C_CPU0_SA_DQS_DN<2>")
	)
	(segment
		(start 328.482452 -271.154144)
		(end 328.094594 -271.542002)
		(width 0.18288)
		(layer "In4.Cu")
		(net "M_C_CPU0_SA_DQS_DN<2>")
	)
	(segment
		(start 326.96658 -272.493994)
		(end 326.578468 -272.882106)
		(width 0.18288)
		(layer "In4.Cu")
		(net "M_C_CPU0_SA_DQS_DN<2>")
	)
	(segment
		(start 300.15688 -294.076628)
		(end 299.502576 -294.076628)
		(width 0.18288)
		(layer "In4.Cu")
		(net "M_C_CPU0_SA_DQS_DN<2>")
	)
	(segment
		(start 325.626476 -274.01012)
		(end 325.238618 -274.397978)
		(width 0.18288)
		(layer "In4.Cu")
		(net "M_C_CPU0_SA_DQS_DN<2>")
	)
	(segment
		(start 336.478118 -268.08049)
		(end 336.477864 -268.080236)
		(width 0.088646)
		(layer "In4.Cu")
		(net "M_C_CPU0_SA_DQS_DN<2>")
	)
	(segment
		(start 327.53046 -271.930114)
		(end 327.53046 -272.106136)
		(width 0.18288)
		(layer "In4.Cu")
		(net "M_C_CPU0_SA_DQS_DN<2>")
	)
	(segment
		(start 319.345564 -280.290778)
		(end 317.581026 -284.550358)
		(width 0.18288)
		(layer "In4.Cu")
		(net "M_C_CPU0_SA_DQS_DN<2>")
	)
	(segment
		(start 324.286626 -275.34997)
		(end 324.110604 -275.34997)
		(width 0.18288)
		(layer "In4.Cu")
		(net "M_C_CPU0_SA_DQS_DN<2>")
	)
	(segment
		(start 299.217842 -293.791894)
		(end 298.809664 -293.791894)
		(width 0.18288)
		(layer "In4.Cu")
		(net "M_C_CPU0_SA_DQS_DN<2>")
	)
	(segment
		(start 332.97622 -268.169644)
		(end 332.745334 -268.400276)
		(width 0.088646)
		(layer "In4.Cu")
		(net "M_C_CPU0_SA_DQS_DN<2>")
	)
	(segment
		(start 313.652154 -288.482786)
		(end 313.511946 -288.62274)
		(width 0.18288)
		(layer "In4.Cu")
		(net "M_C_CPU0_SA_DQS_DN<2>")
	)
	(segment
		(start 329.046586 -270.59001)
		(end 328.870564 -270.59001)
		(width 0.18288)
		(layer "In4.Cu")
		(net "M_C_CPU0_SA_DQS_DN<2>")
	)
	(segment
		(start 338.985606 -267.934694)
		(end 338.732368 -268.08049)
		(width 0.088646)
		(layer "In4.Cu")
		(net "M_C_CPU0_SA_DQS_DN<2>")
	)
	(segment
		(start 304.759868 -292.965378)
		(end 301.26813 -292.965378)
		(width 0.18288)
		(layer "In4.Cu")
		(net "M_C_CPU0_SA_DQS_DN<2>")
	)
	(segment
		(start 324.674484 -274.962112)
		(end 324.286626 -275.34997)
		(width 0.18288)
		(layer "In4.Cu")
		(net "M_C_CPU0_SA_DQS_DN<2>")
	)
	(segment
		(start 292.41877 -293.386764)
		(end 289.007296 -293.386764)
		(width 0.18288)
		(layer "In4.Cu")
		(net "M_C_CPU0_SA_DQS_DN<2>")
	)
	(segment
		(start 322.7705 -276.866096)
		(end 319.345564 -280.290778)
		(width 0.18288)
		(layer "In4.Cu")
		(net "M_C_CPU0_SA_DQS_DN<2>")
	)
	(segment
		(start 294.443912 -294.906446)
		(end 293.938452 -294.906446)
		(width 0.18288)
		(layer "In4.Cu")
		(net "M_C_CPU0_SA_DQS_DN<2>")
	)
	(arc
		(start 335.91246 -268.080236)
		(mid 335.725262 -268.130379)
		(end 335.538064 -268.080236)
		(width 0.088646)
		(layer "In4.Cu")
		(net "M_C_CPU0_SA_DQS_DN<2>")
	)
	(arc
		(start 334.03286 -268.080236)
		(mid 333.845662 -268.130379)
		(end 333.658464 -268.080236)
		(width 0.088646)
		(layer "In4.Cu")
		(net "M_C_CPU0_SA_DQS_DN<2>")
	)
	(arc
		(start 337.792314 -268.080236)
		(mid 337.605006 -268.130379)
		(end 337.417664 -268.080236)
		(width 0.088646)
		(layer "In4.Cu")
		(net "M_C_CPU0_SA_DQS_DN<2>")
	)
	(arc
		(start 339.41385 -267.8938)
		(mid 339.339165 -267.924305)
		(end 339.259164 -267.934694)
		(width 0.088646)
		(layer "In4.Cu")
		(net "M_C_CPU0_SA_DQS_DN<2>")
	)
	(arc
		(start 333.658464 -268.080236)
		(mid 333.376443 -268.004714)
		(end 333.09433 -268.079982)
		(width 0.088646)
		(layer "In4.Cu")
		(net "M_C_CPU0_SA_DQS_DN<2>")
	)
	(arc
		(start 335.538064 -268.080236)
		(mid 335.255362 -268.00446)
		(end 334.97266 -268.080236)
		(width 0.088646)
		(layer "In4.Cu")
		(net "M_C_CPU0_SA_DQS_DN<2>")
	)
	(arc
		(start 338.357464 -268.080236)
		(mid 338.076953 -268.00459)
		(end 337.79587 -268.078204)
		(width 0.088646)
		(layer "In4.Cu")
		(net "M_C_CPU0_SA_DQS_DN<2>")
	)
	(arc
		(start 333.093314 -268.08049)
		(mid 333.031851 -268.121237)
		(end 332.97622 -268.169644)
		(width 0.088646)
		(layer "In4.Cu")
		(net "M_C_CPU0_SA_DQS_DN<2>")
	)
	(arc
		(start 334.598264 -268.080236)
		(mid 334.315562 -268.00446)
		(end 334.03286 -268.080236)
		(width 0.088646)
		(layer "In4.Cu")
		(net "M_C_CPU0_SA_DQS_DN<2>")
	)
	(arc
		(start 333.09433 -268.079982)
		(mid 333.093822 -268.080236)
		(end 333.093314 -268.08049)
		(width 0.088646)
		(layer "In4.Cu")
		(net "M_C_CPU0_SA_DQS_DN<2>")
	)
	(arc
		(start 334.97266 -268.080236)
		(mid 334.785462 -268.130379)
		(end 334.598264 -268.080236)
		(width 0.088646)
		(layer "In4.Cu")
		(net "M_C_CPU0_SA_DQS_DN<2>")
	)
	(arc
		(start 338.732114 -268.080236)
		(mid 338.544916 -268.130379)
		(end 338.357718 -268.080236)
		(width 0.088646)
		(layer "In4.Cu")
		(net "M_C_CPU0_SA_DQS_DN<2>")
	)
	(arc
		(start 336.477864 -268.080236)
		(mid 336.195162 -268.00446)
		(end 335.91246 -268.080236)
		(width 0.088646)
		(layer "In4.Cu")
		(net "M_C_CPU0_SA_DQS_DN<2>")
	)
	(arc
		(start 336.846672 -268.083538)
		(mid 336.66199 -268.13049)
		(end 336.478118 -268.08049)
		(width 0.088646)
		(layer "In4.Cu")
		(net "M_C_CPU0_SA_DQS_DN<2>")
	)
	(arc
		(start 337.417664 -268.080236)
		(mid 337.13772 -268.004592)
		(end 336.857086 -268.077696)
		(width 0.088646)
		(layer "In4.Cu")
		(net "M_C_CPU0_SA_DQS_DN<2>")
	)
	(segment
		(start 276.624288 -303.141634)
		(end 276.469094 -303.141634)
		(width 0.20066)
		(layer "F.Cu")
		(net "M_C_CPU0_SA_DQS_DN<1>")
	)
	(segment
		(start 276.469094 -303.141634)
		(end 274.155408 -303.141634)
		(width 0.1016)
		(layer "F.Cu")
		(net "M_C_CPU0_SA_DQS_DN<1>")
	)
	(segment
		(start 272.491708 -302.977804)
		(end 271.977866 -302.977804)
		(width 0.20066)
		(layer "F.Cu")
		(net "M_C_CPU0_SA_DQS_DN<1>")
	)
	(segment
		(start 273.127724 -303.403)
		(end 272.491708 -302.977804)
		(width 0.20066)
		(layer "F.Cu")
		(net "M_C_CPU0_SA_DQS_DN<1>")
	)
	(segment
		(start 277.49754 -302.977804)
		(end 277.072344 -303.403)
		(width 0.20066)
		(layer "F.Cu")
		(net "M_C_CPU0_SA_DQS_DN<1>")
	)
	(segment
		(start 273.939762 -303.130966)
		(end 273.667728 -303.403)
		(width 0.20066)
		(layer "F.Cu")
		(net "M_C_CPU0_SA_DQS_DN<1>")
	)
	(segment
		(start 273.667728 -303.403)
		(end 273.127724 -303.403)
		(width 0.20066)
		(layer "F.Cu")
		(net "M_C_CPU0_SA_DQS_DN<1>")
	)
	(segment
		(start 271.716754 -302.716692)
		(end 271.168114 -302.716692)
		(width 0.20066)
		(layer "F.Cu")
		(net "M_C_CPU0_SA_DQS_DN<1>")
	)
	(segment
		(start 274.143978 -303.130966)
		(end 273.939762 -303.130966)
		(width 0.20066)
		(layer "F.Cu")
		(net "M_C_CPU0_SA_DQS_DN<1>")
	)
	(segment
		(start 279.816814 -302.716692)
		(end 278.711914 -302.716692)
		(width 0.20066)
		(layer "F.Cu")
		(net "M_C_CPU0_SA_DQS_DN<1>")
	)
	(segment
		(start 274.14474 -303.130966)
		(end 274.143978 -303.130966)
		(width 0.101854)
		(layer "F.Cu")
		(net "M_C_CPU0_SA_DQS_DN<1>")
	)
	(segment
		(start 277.072344 -303.403)
		(end 276.885654 -303.403)
		(width 0.20066)
		(layer "F.Cu")
		(net "M_C_CPU0_SA_DQS_DN<1>")
	)
	(segment
		(start 276.885654 -303.403)
		(end 276.624288 -303.141634)
		(width 0.20066)
		(layer "F.Cu")
		(net "M_C_CPU0_SA_DQS_DN<1>")
	)
	(segment
		(start 277.904194 -302.977804)
		(end 277.49754 -302.977804)
		(width 0.20066)
		(layer "F.Cu")
		(net "M_C_CPU0_SA_DQS_DN<1>")
	)
	(segment
		(start 278.711914 -302.716692)
		(end 278.165306 -302.716692)
		(width 0.20066)
		(layer "F.Cu")
		(net "M_C_CPU0_SA_DQS_DN<1>")
	)
	(segment
		(start 342.773762 -269.66164)
		(end 342.774016 -270.19758)
		(width 0.20066)
		(layer "F.Cu")
		(net "M_C_CPU0_SA_DQS_DN<1>")
	)
	(segment
		(start 274.155408 -303.141634)
		(end 274.14474 -303.130966)
		(width 0.101854)
		(layer "F.Cu")
		(net "M_C_CPU0_SA_DQS_DN<1>")
	)
	(segment
		(start 271.977866 -302.977804)
		(end 271.716754 -302.716692)
		(width 0.20066)
		(layer "F.Cu")
		(net "M_C_CPU0_SA_DQS_DN<1>")
	)
	(segment
		(start 278.165306 -302.716692)
		(end 277.904194 -302.977804)
		(width 0.20066)
		(layer "F.Cu")
		(net "M_C_CPU0_SA_DQS_DN<1>")
	)
	(segment
		(start 284.458156 -303.405032)
		(end 284.194758 -303.141634)
		(width 0.18288)
		(layer "In6.Cu")
		(net "M_C_CPU0_SA_DQS_DN<1>")
	)
	(segment
		(start 317.000128 -284.131004)
		(end 316.612016 -284.519116)
		(width 0.18288)
		(layer "In6.Cu")
		(net "M_C_CPU0_SA_DQS_DN<1>")
	)
	(segment
		(start 284.194758 -303.141634)
		(end 283.694124 -303.141634)
		(width 0.18288)
		(layer "In6.Cu")
		(net "M_C_CPU0_SA_DQS_DN<1>")
	)
	(segment
		(start 317.564008 -283.567124)
		(end 317.564008 -283.743146)
		(width 0.18288)
		(layer "In6.Cu")
		(net "M_C_CPU0_SA_DQS_DN<1>")
	)
	(segment
		(start 323.840094 -277.46706)
		(end 323.664072 -277.46706)
		(width 0.18288)
		(layer "In6.Cu")
		(net "M_C_CPU0_SA_DQS_DN<1>")
	)
	(segment
		(start 334.598264 -271.335754)
		(end 334.583532 -271.327118)
		(width 0.088646)
		(layer "In6.Cu")
		(net "M_C_CPU0_SA_DQS_DN<1>")
	)
	(segment
		(start 282.869132 -303.396396)
		(end 282.535376 -303.06264)
		(width 0.18288)
		(layer "In6.Cu")
		(net "M_C_CPU0_SA_DQS_DN<1>")
	)
	(segment
		(start 334.98155 -271.330674)
		(end 334.97266 -271.335754)
		(width 0.088646)
		(layer "In6.Cu")
		(net "M_C_CPU0_SA_DQS_DN<1>")
	)
	(segment
		(start 320.419984 -280.711148)
		(end 320.419984 -280.88717)
		(width 0.18288)
		(layer "In6.Cu")
		(net "M_C_CPU0_SA_DQS_DN<1>")
	)
	(segment
		(start 299.728128 -294.051482)
		(end 299.517562 -294.051482)
		(width 0.18288)
		(layer "In6.Cu")
		(net "M_C_CPU0_SA_DQS_DN<1>")
	)
	(segment
		(start 324.616064 -276.515068)
		(end 324.227952 -276.90318)
		(width 0.18288)
		(layer "In6.Cu")
		(net "M_C_CPU0_SA_DQS_DN<1>")
	)
	(segment
		(start 282.535376 -303.06264)
		(end 281.89174 -302.796956)
		(width 0.18288)
		(layer "In6.Cu")
		(net "M_C_CPU0_SA_DQS_DN<1>")
	)
	(segment
		(start 290.098226 -300.92396)
		(end 289.450526 -301.57166)
		(width 0.18288)
		(layer "In6.Cu")
		(net "M_C_CPU0_SA_DQS_DN<1>")
	)
	(segment
		(start 321.371976 -279.935178)
		(end 320.984118 -280.323036)
		(width 0.18288)
		(layer "In6.Cu")
		(net "M_C_CPU0_SA_DQS_DN<1>")
	)
	(segment
		(start 321.760088 -279.371044)
		(end 321.371976 -279.759156)
		(width 0.18288)
		(layer "In6.Cu")
		(net "M_C_CPU0_SA_DQS_DN<1>")
	)
	(segment
		(start 317.564008 -283.743146)
		(end 317.17615 -284.131004)
		(width 0.18288)
		(layer "In6.Cu")
		(net "M_C_CPU0_SA_DQS_DN<1>")
	)
	(segment
		(start 319.467992 -281.839162)
		(end 319.080134 -282.22702)
		(width 0.18288)
		(layer "In6.Cu")
		(net "M_C_CPU0_SA_DQS_DN<1>")
	)
	(segment
		(start 333.4004 -272.193004)
		(end 333.087726 -272.193004)
		(width 0.088646)
		(layer "In6.Cu")
		(net "M_C_CPU0_SA_DQS_DN<1>")
	)
	(segment
		(start 297.59656 -294.052752)
		(end 296.989754 -294.659558)
		(width 0.18288)
		(layer "In6.Cu")
		(net "M_C_CPU0_SA_DQS_DN<1>")
	)
	(segment
		(start 296.136822 -294.659558)
		(end 295.871392 -294.924988)
		(width 0.18288)
		(layer "In6.Cu")
		(net "M_C_CPU0_SA_DQS_DN<1>")
	)
	(segment
		(start 338.272374 -270.515842)
		(end 338.26196 -270.521938)
		(width 0.088646)
		(layer "In6.Cu")
		(net "M_C_CPU0_SA_DQS_DN<1>")
	)
	(segment
		(start 296.989754 -294.659558)
		(end 296.136822 -294.659558)
		(width 0.18288)
		(layer "In6.Cu")
		(net "M_C_CPU0_SA_DQS_DN<1>")
	)
	(segment
		(start 298.49445 -294.052752)
		(end 297.59656 -294.052752)
		(width 0.18288)
		(layer "In6.Cu")
		(net "M_C_CPU0_SA_DQS_DN<1>")
	)
	(segment
		(start 332.417166 -273.33829)
		(end 331.87259 -273.882866)
		(width 0.088646)
		(layer "In6.Cu")
		(net "M_C_CPU0_SA_DQS_DN<1>")
	)
	(segment
		(start 316.612016 -284.519116)
		(end 316.612016 -284.695138)
		(width 0.18288)
		(layer "In6.Cu")
		(net "M_C_CPU0_SA_DQS_DN<1>")
	)
	(segment
		(start 333.087726 -272.193004)
		(end 332.417166 -272.863564)
		(width 0.088646)
		(layer "In6.Cu")
		(net "M_C_CPU0_SA_DQS_DN<1>")
	)
	(segment
		(start 320.984118 -280.323036)
		(end 320.808096 -280.323036)
		(width 0.18288)
		(layer "In6.Cu")
		(net "M_C_CPU0_SA_DQS_DN<1>")
	)
	(segment
		(start 322.71208 -278.419052)
		(end 322.323968 -278.807164)
		(width 0.18288)
		(layer "In6.Cu")
		(net "M_C_CPU0_SA_DQS_DN<1>")
	)
	(segment
		(start 298.755816 -293.791386)
		(end 298.49445 -294.052752)
		(width 0.18288)
		(layer "In6.Cu")
		(net "M_C_CPU0_SA_DQS_DN<1>")
	)
	(segment
		(start 295.39057 -294.924988)
		(end 295.107614 -294.642032)
		(width 0.18288)
		(layer "In6.Cu")
		(net "M_C_CPU0_SA_DQS_DN<1>")
	)
	(segment
		(start 299.257466 -293.791386)
		(end 298.755816 -293.791386)
		(width 0.18288)
		(layer "In6.Cu")
		(net "M_C_CPU0_SA_DQS_DN<1>")
	)
	(segment
		(start 320.419984 -280.88717)
		(end 320.032126 -281.275028)
		(width 0.18288)
		(layer "In6.Cu")
		(net "M_C_CPU0_SA_DQS_DN<1>")
	)
	(segment
		(start 295.107614 -294.642032)
		(end 294.681148 -294.642032)
		(width 0.18288)
		(layer "In6.Cu")
		(net "M_C_CPU0_SA_DQS_DN<1>")
	)
	(segment
		(start 318.516 -282.615132)
		(end 318.516 -282.791154)
		(width 0.18288)
		(layer "In6.Cu")
		(net "M_C_CPU0_SA_DQS_DN<1>")
	)
	(segment
		(start 280.828242 -302.987964)
		(end 280.088086 -302.987964)
		(width 0.18288)
		(layer "In6.Cu")
		(net "M_C_CPU0_SA_DQS_DN<1>")
	)
	(segment
		(start 293.200836 -294.310054)
		(end 292.510464 -294.310054)
		(width 0.18288)
		(layer "In6.Cu")
		(net "M_C_CPU0_SA_DQS_DN<1>")
	)
	(segment
		(start 318.516 -282.791154)
		(end 318.128142 -283.179012)
		(width 0.18288)
		(layer "In6.Cu")
		(net "M_C_CPU0_SA_DQS_DN<1>")
	)
	(segment
		(start 322.888102 -278.419052)
		(end 322.71208 -278.419052)
		(width 0.18288)
		(layer "In6.Cu")
		(net "M_C_CPU0_SA_DQS_DN<1>")
	)
	(segment
		(start 332.417166 -272.863564)
		(end 332.417166 -273.33829)
		(width 0.088646)
		(layer "In6.Cu")
		(net "M_C_CPU0_SA_DQS_DN<1>")
	)
	(segment
		(start 312.074306 -287.21177)
		(end 309.62981 -288.224214)
		(width 0.18288)
		(layer "In6.Cu")
		(net "M_C_CPU0_SA_DQS_DN<1>")
	)
	(segment
		(start 302.31715 -291.462206)
		(end 299.728128 -294.051482)
		(width 0.18288)
		(layer "In6.Cu")
		(net "M_C_CPU0_SA_DQS_DN<1>")
	)
	(segment
		(start 317.17615 -284.131004)
		(end 317.000128 -284.131004)
		(width 0.18288)
		(layer "In6.Cu")
		(net "M_C_CPU0_SA_DQS_DN<1>")
	)
	(segment
		(start 342.548718 -270.376396)
		(end 342.27516 -270.376396)
		(width 0.088646)
		(layer "In6.Cu")
		(net "M_C_CPU0_SA_DQS_DN<1>")
	)
	(segment
		(start 331.306424 -273.823176)
		(end 331.283056 -273.823176)
		(width 0.088646)
		(layer "In6.Cu")
		(net "M_C_CPU0_SA_DQS_DN<1>")
	)
	(segment
		(start 290.451794 -295.771062)
		(end 290.098226 -296.625264)
		(width 0.18288)
		(layer "In6.Cu")
		(net "M_C_CPU0_SA_DQS_DN<1>")
	)
	(segment
		(start 307.49875 -288.224214)
		(end 306.969668 -288.753042)
		(width 0.18288)
		(layer "In6.Cu")
		(net "M_C_CPU0_SA_DQS_DN<1>")
	)
	(segment
		(start 319.856104 -281.275028)
		(end 319.467992 -281.66314)
		(width 0.18288)
		(layer "In6.Cu")
		(net "M_C_CPU0_SA_DQS_DN<1>")
	)
	(segment
		(start 320.808096 -280.323036)
		(end 320.419984 -280.711148)
		(width 0.18288)
		(layer "In6.Cu")
		(net "M_C_CPU0_SA_DQS_DN<1>")
	)
	(segment
		(start 319.080134 -282.22702)
		(end 318.904112 -282.22702)
		(width 0.18288)
		(layer "In6.Cu")
		(net "M_C_CPU0_SA_DQS_DN<1>")
	)
	(segment
		(start 322.323968 -278.807164)
		(end 322.323968 -278.983186)
		(width 0.18288)
		(layer "In6.Cu")
		(net "M_C_CPU0_SA_DQS_DN<1>")
	)
	(segment
		(start 341.096346 -270.513302)
		(end 341.081614 -270.521938)
		(width 0.088646)
		(layer "In6.Cu")
		(net "M_C_CPU0_SA_DQS_DN<1>")
	)
	(segment
		(start 291.48913 -294.73398)
		(end 290.451794 -295.771062)
		(width 0.18288)
		(layer "In6.Cu")
		(net "M_C_CPU0_SA_DQS_DN<1>")
	)
	(segment
		(start 289.450526 -301.57166)
		(end 285.025338 -303.405032)
		(width 0.18288)
		(layer "In6.Cu")
		(net "M_C_CPU0_SA_DQS_DN<1>")
	)
	(segment
		(start 323.27596 -278.031194)
		(end 322.888102 -278.419052)
		(width 0.18288)
		(layer "In6.Cu")
		(net "M_C_CPU0_SA_DQS_DN<1>")
	)
	(segment
		(start 309.62981 -288.224214)
		(end 307.49875 -288.224214)
		(width 0.18288)
		(layer "In6.Cu")
		(net "M_C_CPU0_SA_DQS_DN<1>")
	)
	(segment
		(start 305.995324 -289.156648)
		(end 304.660808 -290.491164)
		(width 0.18288)
		(layer "In6.Cu")
		(net "M_C_CPU0_SA_DQS_DN<1>")
	)
	(segment
		(start 318.128142 -283.179012)
		(end 317.95212 -283.179012)
		(width 0.18288)
		(layer "In6.Cu")
		(net "M_C_CPU0_SA_DQS_DN<1>")
	)
	(segment
		(start 342.27516 -270.376396)
		(end 342.021922 -270.522192)
		(width 0.088646)
		(layer "In6.Cu")
		(net "M_C_CPU0_SA_DQS_DN<1>")
	)
	(segment
		(start 324.227952 -277.079202)
		(end 323.840094 -277.46706)
		(width 0.18288)
		(layer "In6.Cu")
		(net "M_C_CPU0_SA_DQS_DN<1>")
	)
	(segment
		(start 321.371976 -279.759156)
		(end 321.371976 -279.935178)
		(width 0.18288)
		(layer "In6.Cu")
		(net "M_C_CPU0_SA_DQS_DN<1>")
	)
	(segment
		(start 335.160112 -270.952722)
		(end 335.160112 -271.011396)
		(width 0.088646)
		(layer "In6.Cu")
		(net "M_C_CPU0_SA_DQS_DN<1>")
	)
	(segment
		(start 281.289506 -302.796956)
		(end 280.828242 -302.987964)
		(width 0.18288)
		(layer "In6.Cu")
		(net "M_C_CPU0_SA_DQS_DN<1>")
	)
	(segment
		(start 285.025338 -303.405032)
		(end 284.458156 -303.405032)
		(width 0.18288)
		(layer "In6.Cu")
		(net "M_C_CPU0_SA_DQS_DN<1>")
	)
	(segment
		(start 324.227952 -276.90318)
		(end 324.227952 -277.079202)
		(width 0.18288)
		(layer "In6.Cu")
		(net "M_C_CPU0_SA_DQS_DN<1>")
	)
	(segment
		(start 339.212428 -270.515842)
		(end 339.202014 -270.521938)
		(width 0.088646)
		(layer "In6.Cu")
		(net "M_C_CPU0_SA_DQS_DN<1>")
	)
	(segment
		(start 342.021922 -270.522192)
		(end 342.021668 -270.521938)
		(width 0.088646)
		(layer "In6.Cu")
		(net "M_C_CPU0_SA_DQS_DN<1>")
	)
	(segment
		(start 292.510464 -294.310054)
		(end 291.99967 -294.522144)
		(width 0.18288)
		(layer "In6.Cu")
		(net "M_C_CPU0_SA_DQS_DN<1>")
	)
	(segment
		(start 323.27596 -277.855172)
		(end 323.27596 -278.031194)
		(width 0.18288)
		(layer "In6.Cu")
		(net "M_C_CPU0_SA_DQS_DN<1>")
	)
	(segment
		(start 290.098226 -296.625264)
		(end 290.098226 -300.92396)
		(width 0.18288)
		(layer "In6.Cu")
		(net "M_C_CPU0_SA_DQS_DN<1>")
	)
	(segment
		(start 325.179944 -276.12721)
		(end 324.79234 -276.515068)
		(width 0.18288)
		(layer "In6.Cu")
		(net "M_C_CPU0_SA_DQS_DN<1>")
	)
	(segment
		(start 341.647272 -270.521938)
		(end 341.647018 -270.521938)
		(width 0.088646)
		(layer "In6.Cu")
		(net "M_C_CPU0_SA_DQS_DN<1>")
	)
	(segment
		(start 293.781734 -294.890952)
		(end 293.200836 -294.310054)
		(width 0.18288)
		(layer "In6.Cu")
		(net "M_C_CPU0_SA_DQS_DN<1>")
	)
	(segment
		(start 323.664072 -277.46706)
		(end 323.27596 -277.855172)
		(width 0.18288)
		(layer "In6.Cu")
		(net "M_C_CPU0_SA_DQS_DN<1>")
	)
	(segment
		(start 331.366114 -273.882866)
		(end 331.306424 -273.823176)
		(width 0.088646)
		(layer "In6.Cu")
		(net "M_C_CPU0_SA_DQS_DN<1>")
	)
	(segment
		(start 306.969668 -288.753042)
		(end 305.995324 -289.156648)
		(width 0.18288)
		(layer "In6.Cu")
		(net "M_C_CPU0_SA_DQS_DN<1>")
	)
	(segment
		(start 294.681148 -294.642032)
		(end 294.432228 -294.890952)
		(width 0.18288)
		(layer "In6.Cu")
		(net "M_C_CPU0_SA_DQS_DN<1>")
	)
	(segment
		(start 304.660808 -290.491164)
		(end 302.31715 -291.462206)
		(width 0.18288)
		(layer "In6.Cu")
		(net "M_C_CPU0_SA_DQS_DN<1>")
	)
	(segment
		(start 315.741304 -285.566104)
		(end 313.719972 -285.566104)
		(width 0.18288)
		(layer "In6.Cu")
		(net "M_C_CPU0_SA_DQS_DN<1>")
	)
	(segment
		(start 318.904112 -282.22702)
		(end 318.516 -282.615132)
		(width 0.18288)
		(layer "In6.Cu")
		(net "M_C_CPU0_SA_DQS_DN<1>")
	)
	(segment
		(start 331.283056 -273.823176)
		(end 330.742798 -273.823176)
		(width 0.18288)
		(layer "In6.Cu")
		(net "M_C_CPU0_SA_DQS_DN<1>")
	)
	(segment
		(start 316.612016 -284.695138)
		(end 315.741304 -285.566104)
		(width 0.18288)
		(layer "In6.Cu")
		(net "M_C_CPU0_SA_DQS_DN<1>")
	)
	(segment
		(start 324.79234 -276.515068)
		(end 324.616064 -276.515068)
		(width 0.18288)
		(layer "In6.Cu")
		(net "M_C_CPU0_SA_DQS_DN<1>")
	)
	(segment
		(start 330.742798 -273.823176)
		(end 325.179944 -276.12721)
		(width 0.18288)
		(layer "In6.Cu")
		(net "M_C_CPU0_SA_DQS_DN<1>")
	)
	(segment
		(start 317.95212 -283.179012)
		(end 317.564008 -283.567124)
		(width 0.18288)
		(layer "In6.Cu")
		(net "M_C_CPU0_SA_DQS_DN<1>")
	)
	(segment
		(start 333.750666 -271.809718)
		(end 333.750666 -271.825212)
		(width 0.088646)
		(layer "In6.Cu")
		(net "M_C_CPU0_SA_DQS_DN<1>")
	)
	(segment
		(start 283.439362 -303.396396)
		(end 282.869132 -303.396396)
		(width 0.18288)
		(layer "In6.Cu")
		(net "M_C_CPU0_SA_DQS_DN<1>")
	)
	(segment
		(start 299.517562 -294.051482)
		(end 299.257466 -293.791386)
		(width 0.18288)
		(layer "In6.Cu")
		(net "M_C_CPU0_SA_DQS_DN<1>")
	)
	(segment
		(start 322.323968 -278.983186)
		(end 321.93611 -279.371044)
		(width 0.18288)
		(layer "In6.Cu")
		(net "M_C_CPU0_SA_DQS_DN<1>")
	)
	(segment
		(start 295.871392 -294.924988)
		(end 295.39057 -294.924988)
		(width 0.18288)
		(layer "In6.Cu")
		(net "M_C_CPU0_SA_DQS_DN<1>")
	)
	(segment
		(start 342.774016 -270.19758)
		(end 342.742266 -270.313404)
		(width 0.088646)
		(layer "In6.Cu")
		(net "M_C_CPU0_SA_DQS_DN<1>")
	)
	(segment
		(start 281.89174 -302.796956)
		(end 281.289506 -302.796956)
		(width 0.18288)
		(layer "In6.Cu")
		(net "M_C_CPU0_SA_DQS_DN<1>")
	)
	(segment
		(start 320.032126 -281.275028)
		(end 319.856104 -281.275028)
		(width 0.18288)
		(layer "In6.Cu")
		(net "M_C_CPU0_SA_DQS_DN<1>")
	)
	(segment
		(start 335.171288 -270.898112)
		(end 335.160112 -270.952722)
		(width 0.088646)
		(layer "In6.Cu")
		(net "M_C_CPU0_SA_DQS_DN<1>")
	)
	(segment
		(start 283.694124 -303.141634)
		(end 283.439362 -303.396396)
		(width 0.18288)
		(layer "In6.Cu")
		(net "M_C_CPU0_SA_DQS_DN<1>")
	)
	(segment
		(start 291.99967 -294.522144)
		(end 291.48913 -294.73398)
		(width 0.18288)
		(layer "In6.Cu")
		(net "M_C_CPU0_SA_DQS_DN<1>")
	)
	(segment
		(start 342.742266 -270.313404)
		(end 342.703404 -270.335502)
		(width 0.088646)
		(layer "In6.Cu")
		(net "M_C_CPU0_SA_DQS_DN<1>")
	)
	(segment
		(start 321.93611 -279.371044)
		(end 321.760088 -279.371044)
		(width 0.18288)
		(layer "In6.Cu")
		(net "M_C_CPU0_SA_DQS_DN<1>")
	)
	(segment
		(start 340.151974 -270.515842)
		(end 340.14156 -270.521938)
		(width 0.088646)
		(layer "In6.Cu")
		(net "M_C_CPU0_SA_DQS_DN<1>")
	)
	(segment
		(start 294.432228 -294.890952)
		(end 293.781734 -294.890952)
		(width 0.18288)
		(layer "In6.Cu")
		(net "M_C_CPU0_SA_DQS_DN<1>")
	)
	(segment
		(start 319.467992 -281.66314)
		(end 319.467992 -281.839162)
		(width 0.18288)
		(layer "In6.Cu")
		(net "M_C_CPU0_SA_DQS_DN<1>")
	)
	(segment
		(start 331.87259 -273.882866)
		(end 331.366114 -273.882866)
		(width 0.088646)
		(layer "In6.Cu")
		(net "M_C_CPU0_SA_DQS_DN<1>")
	)
	(segment
		(start 313.719972 -285.566104)
		(end 312.074306 -287.21177)
		(width 0.18288)
		(layer "In6.Cu")
		(net "M_C_CPU0_SA_DQS_DN<1>")
	)
	(segment
		(start 280.088086 -302.987964)
		(end 279.816814 -302.716692)
		(width 0.18288)
		(layer "In6.Cu")
		(net "M_C_CPU0_SA_DQS_DN<1>")
	)
	(arc
		(start 339.767164 -270.521938)
		(mid 339.490605 -270.446195)
		(end 339.212428 -270.515842)
		(width 0.088646)
		(layer "In6.Cu")
		(net "M_C_CPU0_SA_DQS_DN<1>")
	)
	(arc
		(start 333.572104 -272.14449)
		(mid 333.489617 -272.180664)
		(end 333.4004 -272.193004)
		(width 0.088646)
		(layer "In6.Cu")
		(net "M_C_CPU0_SA_DQS_DN<1>")
	)
	(arc
		(start 336.007964 -270.521938)
		(mid 335.493229 -270.49573)
		(end 335.171288 -270.898112)
		(width 0.088646)
		(layer "In6.Cu")
		(net "M_C_CPU0_SA_DQS_DN<1>")
	)
	(arc
		(start 337.887564 -270.521938)
		(mid 337.604862 -270.446162)
		(end 337.32216 -270.521938)
		(width 0.088646)
		(layer "In6.Cu")
		(net "M_C_CPU0_SA_DQS_DN<1>")
	)
	(arc
		(start 342.703404 -270.335502)
		(mid 342.628719 -270.366007)
		(end 342.548718 -270.376396)
		(width 0.088646)
		(layer "In6.Cu")
		(net "M_C_CPU0_SA_DQS_DN<1>")
	)
	(arc
		(start 339.202014 -270.521938)
		(mid 339.014816 -270.572081)
		(end 338.827618 -270.521938)
		(width 0.088646)
		(layer "In6.Cu")
		(net "M_C_CPU0_SA_DQS_DN<1>")
	)
	(arc
		(start 335.160112 -271.011396)
		(mid 335.112433 -271.194296)
		(end 334.98155 -271.330674)
		(width 0.088646)
		(layer "In6.Cu")
		(net "M_C_CPU0_SA_DQS_DN<1>")
	)
	(arc
		(start 341.647018 -270.521938)
		(mid 341.372819 -270.446103)
		(end 341.096346 -270.513302)
		(width 0.088646)
		(layer "In6.Cu")
		(net "M_C_CPU0_SA_DQS_DN<1>")
	)
	(arc
		(start 338.827618 -270.521938)
		(mid 338.550805 -270.446068)
		(end 338.272374 -270.515842)
		(width 0.088646)
		(layer "In6.Cu")
		(net "M_C_CPU0_SA_DQS_DN<1>")
	)
	(arc
		(start 336.947764 -270.521938)
		(mid 336.665062 -270.446162)
		(end 336.38236 -270.521938)
		(width 0.088646)
		(layer "In6.Cu")
		(net "M_C_CPU0_SA_DQS_DN<1>")
	)
	(arc
		(start 342.021668 -270.521938)
		(mid 341.83447 -270.572081)
		(end 341.647272 -270.521938)
		(width 0.088646)
		(layer "In6.Cu")
		(net "M_C_CPU0_SA_DQS_DN<1>")
	)
	(arc
		(start 334.97266 -271.335754)
		(mid 334.785462 -271.385897)
		(end 334.598264 -271.335754)
		(width 0.088646)
		(layer "In6.Cu")
		(net "M_C_CPU0_SA_DQS_DN<1>")
	)
	(arc
		(start 333.750666 -271.825212)
		(mid 333.702987 -272.008112)
		(end 333.572104 -272.14449)
		(width 0.088646)
		(layer "In6.Cu")
		(net "M_C_CPU0_SA_DQS_DN<1>")
	)
	(arc
		(start 336.38236 -270.521938)
		(mid 336.195162 -270.572081)
		(end 336.007964 -270.521938)
		(width 0.088646)
		(layer "In6.Cu")
		(net "M_C_CPU0_SA_DQS_DN<1>")
	)
	(arc
		(start 341.081614 -270.521938)
		(mid 340.894416 -270.572081)
		(end 340.707218 -270.521938)
		(width 0.088646)
		(layer "In6.Cu")
		(net "M_C_CPU0_SA_DQS_DN<1>")
	)
	(arc
		(start 340.707218 -270.521938)
		(mid 340.430405 -270.446068)
		(end 340.151974 -270.515842)
		(width 0.088646)
		(layer "In6.Cu")
		(net "M_C_CPU0_SA_DQS_DN<1>")
	)
	(arc
		(start 338.26196 -270.521938)
		(mid 338.074762 -270.572081)
		(end 337.887564 -270.521938)
		(width 0.088646)
		(layer "In6.Cu")
		(net "M_C_CPU0_SA_DQS_DN<1>")
	)
	(arc
		(start 334.03286 -271.335754)
		(mid 333.830037 -271.535985)
		(end 333.750666 -271.809718)
		(width 0.088646)
		(layer "In6.Cu")
		(net "M_C_CPU0_SA_DQS_DN<1>")
	)
	(arc
		(start 340.14156 -270.521938)
		(mid 339.954362 -270.572081)
		(end 339.767164 -270.521938)
		(width 0.088646)
		(layer "In6.Cu")
		(net "M_C_CPU0_SA_DQS_DN<1>")
	)
	(arc
		(start 337.32216 -270.521938)
		(mid 337.134962 -270.572081)
		(end 336.947764 -270.521938)
		(width 0.088646)
		(layer "In6.Cu")
		(net "M_C_CPU0_SA_DQS_DN<1>")
	)
	(arc
		(start 334.583532 -271.327118)
		(mid 334.307057 -271.259798)
		(end 334.03286 -271.335754)
		(width 0.088646)
		(layer "In6.Cu")
		(net "M_C_CPU0_SA_DQS_DN<1>")
	)
	(segment
		(start 278.165306 -312.066686)
		(end 277.904194 -312.327798)
		(width 0.20066)
		(layer "F.Cu")
		(net "M_C_CPU0_SA_DQS_DN<0>")
	)
	(segment
		(start 274.155408 -312.491628)
		(end 274.14474 -312.48096)
		(width 0.101854)
		(layer "F.Cu")
		(net "M_C_CPU0_SA_DQS_DN<0>")
	)
	(segment
		(start 274.143978 -312.48096)
		(end 273.939762 -312.48096)
		(width 0.20066)
		(layer "F.Cu")
		(net "M_C_CPU0_SA_DQS_DN<0>")
	)
	(segment
		(start 277.904194 -312.327798)
		(end 277.49754 -312.327798)
		(width 0.20066)
		(layer "F.Cu")
		(net "M_C_CPU0_SA_DQS_DN<0>")
	)
	(segment
		(start 277.49754 -312.327798)
		(end 277.072344 -312.752994)
		(width 0.20066)
		(layer "F.Cu")
		(net "M_C_CPU0_SA_DQS_DN<0>")
	)
	(segment
		(start 274.14474 -312.48096)
		(end 274.143978 -312.48096)
		(width 0.101854)
		(layer "F.Cu")
		(net "M_C_CPU0_SA_DQS_DN<0>")
	)
	(segment
		(start 277.072344 -312.752994)
		(end 276.885654 -312.752994)
		(width 0.20066)
		(layer "F.Cu")
		(net "M_C_CPU0_SA_DQS_DN<0>")
	)
	(segment
		(start 273.667728 -312.752994)
		(end 273.127724 -312.752994)
		(width 0.20066)
		(layer "F.Cu")
		(net "M_C_CPU0_SA_DQS_DN<0>")
	)
	(segment
		(start 273.939762 -312.48096)
		(end 273.667728 -312.752994)
		(width 0.20066)
		(layer "F.Cu")
		(net "M_C_CPU0_SA_DQS_DN<0>")
	)
	(segment
		(start 276.624288 -312.491628)
		(end 276.469094 -312.491628)
		(width 0.20066)
		(layer "F.Cu")
		(net "M_C_CPU0_SA_DQS_DN<0>")
	)
	(segment
		(start 278.711914 -312.066686)
		(end 278.165306 -312.066686)
		(width 0.20066)
		(layer "F.Cu")
		(net "M_C_CPU0_SA_DQS_DN<0>")
	)
	(segment
		(start 276.469094 -312.491628)
		(end 274.155408 -312.491628)
		(width 0.1016)
		(layer "F.Cu")
		(net "M_C_CPU0_SA_DQS_DN<0>")
	)
	(segment
		(start 276.885654 -312.752994)
		(end 276.624288 -312.491628)
		(width 0.20066)
		(layer "F.Cu")
		(net "M_C_CPU0_SA_DQS_DN<0>")
	)
	(segment
		(start 272.491708 -312.327798)
		(end 271.977866 -312.327798)
		(width 0.20066)
		(layer "F.Cu")
		(net "M_C_CPU0_SA_DQS_DN<0>")
	)
	(segment
		(start 339.484716 -276.986492)
		(end 339.484716 -277.522178)
		(width 0.20066)
		(layer "F.Cu")
		(net "M_C_CPU0_SA_DQS_DN<0>")
	)
	(segment
		(start 339.484716 -277.522178)
		(end 339.484462 -277.522432)
		(width 0.20066)
		(layer "F.Cu")
		(net "M_C_CPU0_SA_DQS_DN<0>")
	)
	(segment
		(start 271.716754 -312.066686)
		(end 271.168114 -312.066686)
		(width 0.20066)
		(layer "F.Cu")
		(net "M_C_CPU0_SA_DQS_DN<0>")
	)
	(segment
		(start 279.816814 -312.066686)
		(end 278.711914 -312.066686)
		(width 0.20066)
		(layer "F.Cu")
		(net "M_C_CPU0_SA_DQS_DN<0>")
	)
	(segment
		(start 271.977866 -312.327798)
		(end 271.716754 -312.066686)
		(width 0.20066)
		(layer "F.Cu")
		(net "M_C_CPU0_SA_DQS_DN<0>")
	)
	(segment
		(start 273.127724 -312.752994)
		(end 272.491708 -312.327798)
		(width 0.20066)
		(layer "F.Cu")
		(net "M_C_CPU0_SA_DQS_DN<0>")
	)
	(segment
		(start 336.39125 -283.539184)
		(end 336.38236 -283.544264)
		(width 0.088646)
		(layer "In4.Cu")
		(net "M_C_CPU0_SA_DQS_DN<0>")
	)
	(segment
		(start 304.736754 -313.668156)
		(end 303.735994 -313.668156)
		(width 0.18288)
		(layer "In4.Cu")
		(net "M_C_CPU0_SA_DQS_DN<0>")
	)
	(segment
		(start 324.456806 -299.285406)
		(end 324.068948 -299.673264)
		(width 0.18288)
		(layer "In4.Cu")
		(net "M_C_CPU0_SA_DQS_DN<0>")
	)
	(segment
		(start 326.36079 -297.381422)
		(end 325.972932 -297.76928)
		(width 0.18288)
		(layer "In4.Cu")
		(net "M_C_CPU0_SA_DQS_DN<0>")
	)
	(segment
		(start 283.722064 -312.491628)
		(end 283.467048 -312.746644)
		(width 0.18288)
		(layer "In4.Cu")
		(net "M_C_CPU0_SA_DQS_DN<0>")
	)
	(segment
		(start 321.988942 -301.577248)
		(end 321.60083 -301.96536)
		(width 0.18288)
		(layer "In4.Cu")
		(net "M_C_CPU0_SA_DQS_DN<0>")
	)
	(segment
		(start 297.823636 -314.439808)
		(end 296.966386 -315.297058)
		(width 0.18288)
		(layer "In4.Cu")
		(net "M_C_CPU0_SA_DQS_DN<0>")
	)
	(segment
		(start 325.02094 -298.721272)
		(end 324.844918 -298.721272)
		(width 0.18288)
		(layer "In4.Cu")
		(net "M_C_CPU0_SA_DQS_DN<0>")
	)
	(segment
		(start 322.552822 -301.013368)
		(end 322.552822 -301.18939)
		(width 0.18288)
		(layer "In4.Cu")
		(net "M_C_CPU0_SA_DQS_DN<0>")
	)
	(segment
		(start 294.710104 -315.041788)
		(end 294.446452 -315.30544)
		(width 0.18288)
		(layer "In4.Cu")
		(net "M_C_CPU0_SA_DQS_DN<0>")
	)
	(segment
		(start 332.192122 -286.20212)
		(end 330.143612 -288.25063)
		(width 0.18288)
		(layer "In4.Cu")
		(net "M_C_CPU0_SA_DQS_DN<0>")
	)
	(segment
		(start 315.732922 -309.925466)
		(end 314.637166 -311.021222)
		(width 0.18288)
		(layer "In4.Cu")
		(net "M_C_CPU0_SA_DQS_DN<0>")
	)
	(segment
		(start 338.27085 -278.65578)
		(end 338.26196 -278.66086)
		(width 0.088646)
		(layer "In4.Cu")
		(net "M_C_CPU0_SA_DQS_DN<0>")
	)
	(segment
		(start 336.867246 -282.721558)
		(end 336.852514 -282.730194)
		(width 0.088646)
		(layer "In4.Cu")
		(net "M_C_CPU0_SA_DQS_DN<0>")
	)
	(segment
		(start 314.637166 -311.021222)
		(end 312.410094 -311.94375)
		(width 0.18288)
		(layer "In4.Cu")
		(net "M_C_CPU0_SA_DQS_DN<0>")
	)
	(segment
		(start 325.408798 -298.157392)
		(end 325.408798 -298.333414)
		(width 0.18288)
		(layer "In4.Cu")
		(net "M_C_CPU0_SA_DQS_DN<0>")
	)
	(segment
		(start 336.569812 -283.205682)
		(end 336.569812 -283.219906)
		(width 0.088646)
		(layer "In4.Cu")
		(net "M_C_CPU0_SA_DQS_DN<0>")
	)
	(segment
		(start 306.46116 -311.94375)
		(end 304.736754 -313.668156)
		(width 0.18288)
		(layer "In4.Cu")
		(net "M_C_CPU0_SA_DQS_DN<0>")
	)
	(segment
		(start 335.92135 -284.353)
		(end 335.91246 -284.35808)
		(width 0.088646)
		(layer "In4.Cu")
		(net "M_C_CPU0_SA_DQS_DN<0>")
	)
	(segment
		(start 332.966568 -285.740856)
		(end 332.881478 -285.740856)
		(width 0.088646)
		(layer "In4.Cu")
		(net "M_C_CPU0_SA_DQS_DN<0>")
	)
	(segment
		(start 295.104312 -315.041788)
		(end 294.710104 -315.041788)
		(width 0.18288)
		(layer "In4.Cu")
		(net "M_C_CPU0_SA_DQS_DN<0>")
	)
	(segment
		(start 337.786218 -282.077922)
		(end 337.792314 -282.081478)
		(width 0.088646)
		(layer "In4.Cu")
		(net "M_C_CPU0_SA_DQS_DN<0>")
	)
	(segment
		(start 316.297056 -309.361332)
		(end 316.121034 -309.361332)
		(width 0.18288)
		(layer "In4.Cu")
		(net "M_C_CPU0_SA_DQS_DN<0>")
	)
	(segment
		(start 318.588898 -306.893468)
		(end 318.588898 -307.06949)
		(width 0.18288)
		(layer "In4.Cu")
		(net "M_C_CPU0_SA_DQS_DN<0>")
	)
	(segment
		(start 292.707822 -314.497466)
		(end 291.864034 -313.653932)
		(width 0.18288)
		(layer "In4.Cu")
		(net "M_C_CPU0_SA_DQS_DN<0>")
	)
	(segment
		(start 338.27085 -280.283412)
		(end 338.26196 -280.288492)
		(width 0.088646)
		(layer "In4.Cu")
		(net "M_C_CPU0_SA_DQS_DN<0>")
	)
	(segment
		(start 287.347152 -312.76544)
		(end 284.388052 -312.76544)
		(width 0.18288)
		(layer "In4.Cu")
		(net "M_C_CPU0_SA_DQS_DN<0>")
	)
	(segment
		(start 337.792314 -282.081478)
		(end 337.792314 -282.081732)
		(width 0.088646)
		(layer "In4.Cu")
		(net "M_C_CPU0_SA_DQS_DN<0>")
	)
	(segment
		(start 337.979512 -280.759662)
		(end 337.979512 -280.778204)
		(width 0.088646)
		(layer "In4.Cu")
		(net "M_C_CPU0_SA_DQS_DN<0>")
	)
	(segment
		(start 325.408798 -298.333414)
		(end 325.02094 -298.721272)
		(width 0.18288)
		(layer "In4.Cu")
		(net "M_C_CPU0_SA_DQS_DN<0>")
	)
	(segment
		(start 322.940934 -300.625256)
		(end 322.552822 -301.013368)
		(width 0.18288)
		(layer "In4.Cu")
		(net "M_C_CPU0_SA_DQS_DN<0>")
	)
	(segment
		(start 319.153032 -306.505356)
		(end 318.97701 -306.505356)
		(width 0.18288)
		(layer "In4.Cu")
		(net "M_C_CPU0_SA_DQS_DN<0>")
	)
	(segment
		(start 336.38236 -283.544264)
		(end 336.376264 -283.54782)
		(width 0.088646)
		(layer "In4.Cu")
		(net "M_C_CPU0_SA_DQS_DN<0>")
	)
	(segment
		(start 321.60083 -302.141382)
		(end 321.212972 -302.52924)
		(width 0.18288)
		(layer "In4.Cu")
		(net "M_C_CPU0_SA_DQS_DN<0>")
	)
	(segment
		(start 320.648838 -302.917352)
		(end 320.648838 -303.093374)
		(width 0.18288)
		(layer "In4.Cu")
		(net "M_C_CPU0_SA_DQS_DN<0>")
	)
	(segment
		(start 317.636906 -308.021482)
		(end 317.249048 -308.40934)
		(width 0.18288)
		(layer "In4.Cu")
		(net "M_C_CPU0_SA_DQS_DN<0>")
	)
	(segment
		(start 316.684914 -308.973474)
		(end 316.297056 -309.361332)
		(width 0.18288)
		(layer "In4.Cu")
		(net "M_C_CPU0_SA_DQS_DN<0>")
	)
	(segment
		(start 324.456806 -299.109384)
		(end 324.456806 -299.285406)
		(width 0.18288)
		(layer "In4.Cu")
		(net "M_C_CPU0_SA_DQS_DN<0>")
	)
	(segment
		(start 315.732922 -309.749444)
		(end 315.732922 -309.925466)
		(width 0.18288)
		(layer "In4.Cu")
		(net "M_C_CPU0_SA_DQS_DN<0>")
	)
	(segment
		(start 322.552822 -301.18939)
		(end 322.164964 -301.577248)
		(width 0.18288)
		(layer "In4.Cu")
		(net "M_C_CPU0_SA_DQS_DN<0>")
	)
	(segment
		(start 320.648838 -303.093374)
		(end 319.54089 -304.201576)
		(width 0.18288)
		(layer "In4.Cu")
		(net "M_C_CPU0_SA_DQS_DN<0>")
	)
	(segment
		(start 338.265262 -279.641808)
		(end 338.27085 -279.644856)
		(width 0.088646)
		(layer "In4.Cu")
		(net "M_C_CPU0_SA_DQS_DN<0>")
	)
	(segment
		(start 318.025018 -307.457348)
		(end 317.636906 -307.84546)
		(width 0.18288)
		(layer "In4.Cu")
		(net "M_C_CPU0_SA_DQS_DN<0>")
	)
	(segment
		(start 298.563538 -314.439808)
		(end 297.823636 -314.439808)
		(width 0.18288)
		(layer "In4.Cu")
		(net "M_C_CPU0_SA_DQS_DN<0>")
	)
	(segment
		(start 324.068948 -299.673264)
		(end 323.892926 -299.673264)
		(width 0.18288)
		(layer "In4.Cu")
		(net "M_C_CPU0_SA_DQS_DN<0>")
	)
	(segment
		(start 280.080974 -312.330846)
		(end 279.816814 -312.066686)
		(width 0.18288)
		(layer "In4.Cu")
		(net "M_C_CPU0_SA_DQS_DN<0>")
	)
	(segment
		(start 332.881478 -285.740856)
		(end 332.859126 -285.763208)
		(width 0.088646)
		(layer "In4.Cu")
		(net "M_C_CPU0_SA_DQS_DN<0>")
	)
	(segment
		(start 295.359582 -315.297058)
		(end 295.104312 -315.041788)
		(width 0.18288)
		(layer "In4.Cu")
		(net "M_C_CPU0_SA_DQS_DN<0>")
	)
	(segment
		(start 332.420214 -286.20212)
		(end 332.192122 -286.20212)
		(width 0.18288)
		(layer "In4.Cu")
		(net "M_C_CPU0_SA_DQS_DN<0>")
	)
	(segment
		(start 337.509612 -281.591766)
		(end 337.509612 -281.59202)
		(width 0.088646)
		(layer "In4.Cu")
		(net "M_C_CPU0_SA_DQS_DN<0>")
	)
	(segment
		(start 323.504814 -300.237398)
		(end 323.116956 -300.625256)
		(width 0.18288)
		(layer "In4.Cu")
		(net "M_C_CPU0_SA_DQS_DN<0>")
	)
	(segment
		(start 338.449412 -278.322278)
		(end 338.449412 -278.336502)
		(width 0.088646)
		(layer "In4.Cu")
		(net "M_C_CPU0_SA_DQS_DN<0>")
	)
	(segment
		(start 289.491166 -313.653932)
		(end 287.347152 -312.76544)
		(width 0.18288)
		(layer "In4.Cu")
		(net "M_C_CPU0_SA_DQS_DN<0>")
	)
	(segment
		(start 321.60083 -301.96536)
		(end 321.60083 -302.141382)
		(width 0.18288)
		(layer "In4.Cu")
		(net "M_C_CPU0_SA_DQS_DN<0>")
	)
	(segment
		(start 302.947832 -314.456318)
		(end 299.472604 -314.456318)
		(width 0.18288)
		(layer "In4.Cu")
		(net "M_C_CPU0_SA_DQS_DN<0>")
	)
	(segment
		(start 282.321508 -312.128662)
		(end 280.599388 -312.128662)
		(width 0.18288)
		(layer "In4.Cu")
		(net "M_C_CPU0_SA_DQS_DN<0>")
	)
	(segment
		(start 321.212972 -302.52924)
		(end 321.03695 -302.52924)
		(width 0.18288)
		(layer "In4.Cu")
		(net "M_C_CPU0_SA_DQS_DN<0>")
	)
	(segment
		(start 339.452712 -277.638256)
		(end 339.41385 -277.660354)
		(width 0.088646)
		(layer "In4.Cu")
		(net "M_C_CPU0_SA_DQS_DN<0>")
	)
	(segment
		(start 316.684914 -308.797452)
		(end 316.684914 -308.973474)
		(width 0.18288)
		(layer "In4.Cu")
		(net "M_C_CPU0_SA_DQS_DN<0>")
	)
	(segment
		(start 335.630012 -284.837632)
		(end 335.630012 -284.847538)
		(width 0.088646)
		(layer "In4.Cu")
		(net "M_C_CPU0_SA_DQS_DN<0>")
	)
	(segment
		(start 323.892926 -299.673264)
		(end 323.504814 -300.061376)
		(width 0.18288)
		(layer "In4.Cu")
		(net "M_C_CPU0_SA_DQS_DN<0>")
	)
	(segment
		(start 317.636906 -307.84546)
		(end 317.636906 -308.021482)
		(width 0.18288)
		(layer "In4.Cu")
		(net "M_C_CPU0_SA_DQS_DN<0>")
	)
	(segment
		(start 299.472604 -314.456318)
		(end 299.207936 -314.19165)
		(width 0.18288)
		(layer "In4.Cu")
		(net "M_C_CPU0_SA_DQS_DN<0>")
	)
	(segment
		(start 280.397204 -312.330846)
		(end 280.080974 -312.330846)
		(width 0.18288)
		(layer "In4.Cu")
		(net "M_C_CPU0_SA_DQS_DN<0>")
	)
	(segment
		(start 323.116956 -300.625256)
		(end 322.940934 -300.625256)
		(width 0.18288)
		(layer "In4.Cu")
		(net "M_C_CPU0_SA_DQS_DN<0>")
	)
	(segment
		(start 296.966386 -315.297058)
		(end 295.359582 -315.297058)
		(width 0.18288)
		(layer "In4.Cu")
		(net "M_C_CPU0_SA_DQS_DN<0>")
	)
	(segment
		(start 338.262722 -279.640284)
		(end 338.265262 -279.641808)
		(width 0.088646)
		(layer "In4.Cu")
		(net "M_C_CPU0_SA_DQS_DN<0>")
	)
	(segment
		(start 337.979512 -279.140412)
		(end 337.979512 -279.160224)
		(width 0.088646)
		(layer "In4.Cu")
		(net "M_C_CPU0_SA_DQS_DN<0>")
	)
	(segment
		(start 338.26196 -279.639776)
		(end 338.262722 -279.640284)
		(width 0.088646)
		(layer "In4.Cu")
		(net "M_C_CPU0_SA_DQS_DN<0>")
	)
	(segment
		(start 324.844918 -298.721272)
		(end 324.456806 -299.109384)
		(width 0.18288)
		(layer "In4.Cu")
		(net "M_C_CPU0_SA_DQS_DN<0>")
	)
	(segment
		(start 312.410094 -311.94375)
		(end 306.46116 -311.94375)
		(width 0.18288)
		(layer "In4.Cu")
		(net "M_C_CPU0_SA_DQS_DN<0>")
	)
	(segment
		(start 283.467048 -312.746644)
		(end 282.93949 -312.746644)
		(width 0.18288)
		(layer "In4.Cu")
		(net "M_C_CPU0_SA_DQS_DN<0>")
	)
	(segment
		(start 319.54089 -306.117498)
		(end 319.153032 -306.505356)
		(width 0.18288)
		(layer "In4.Cu")
		(net "M_C_CPU0_SA_DQS_DN<0>")
	)
	(segment
		(start 330.143612 -288.25063)
		(end 326.36079 -297.381422)
		(width 0.18288)
		(layer "In4.Cu")
		(net "M_C_CPU0_SA_DQS_DN<0>")
	)
	(segment
		(start 323.504814 -300.061376)
		(end 323.504814 -300.237398)
		(width 0.18288)
		(layer "In4.Cu")
		(net "M_C_CPU0_SA_DQS_DN<0>")
	)
	(segment
		(start 321.03695 -302.52924)
		(end 320.648838 -302.917352)
		(width 0.18288)
		(layer "In4.Cu")
		(net "M_C_CPU0_SA_DQS_DN<0>")
	)
	(segment
		(start 318.20104 -307.457348)
		(end 318.025018 -307.457348)
		(width 0.18288)
		(layer "In4.Cu")
		(net "M_C_CPU0_SA_DQS_DN<0>")
	)
	(segment
		(start 299.207936 -314.19165)
		(end 298.811696 -314.19165)
		(width 0.18288)
		(layer "In4.Cu")
		(net "M_C_CPU0_SA_DQS_DN<0>")
	)
	(segment
		(start 325.972932 -297.76928)
		(end 325.79691 -297.76928)
		(width 0.18288)
		(layer "In4.Cu")
		(net "M_C_CPU0_SA_DQS_DN<0>")
	)
	(segment
		(start 333.448152 -285.259526)
		(end 333.26451 -285.44266)
		(width 0.088646)
		(layer "In4.Cu")
		(net "M_C_CPU0_SA_DQS_DN<0>")
	)
	(segment
		(start 294.446452 -315.30544)
		(end 293.974012 -315.30544)
		(width 0.18288)
		(layer "In4.Cu")
		(net "M_C_CPU0_SA_DQS_DN<0>")
	)
	(segment
		(start 280.599388 -312.128662)
		(end 280.397204 -312.330846)
		(width 0.18288)
		(layer "In4.Cu")
		(net "M_C_CPU0_SA_DQS_DN<0>")
	)
	(segment
		(start 338.73059 -277.848314)
		(end 338.732114 -277.84679)
		(width 0.088646)
		(layer "In4.Cu")
		(net "M_C_CPU0_SA_DQS_DN<0>")
	)
	(segment
		(start 318.97701 -306.505356)
		(end 318.588898 -306.893468)
		(width 0.18288)
		(layer "In4.Cu")
		(net "M_C_CPU0_SA_DQS_DN<0>")
	)
	(segment
		(start 293.974012 -315.30544)
		(end 293.49065 -314.821824)
		(width 0.18288)
		(layer "In4.Cu")
		(net "M_C_CPU0_SA_DQS_DN<0>")
	)
	(segment
		(start 337.792314 -282.72994)
		(end 337.792314 -282.730194)
		(width 0.088646)
		(layer "In4.Cu")
		(net "M_C_CPU0_SA_DQS_DN<0>")
	)
	(segment
		(start 317.073026 -308.40934)
		(end 316.684914 -308.797452)
		(width 0.18288)
		(layer "In4.Cu")
		(net "M_C_CPU0_SA_DQS_DN<0>")
	)
	(segment
		(start 303.735994 -313.668156)
		(end 302.947832 -314.456318)
		(width 0.18288)
		(layer "In4.Cu")
		(net "M_C_CPU0_SA_DQS_DN<0>")
	)
	(segment
		(start 325.79691 -297.76928)
		(end 325.408798 -298.157392)
		(width 0.18288)
		(layer "In4.Cu")
		(net "M_C_CPU0_SA_DQS_DN<0>")
	)
	(segment
		(start 333.26451 -285.44266)
		(end 332.966568 -285.740856)
		(width 0.088646)
		(layer "In4.Cu")
		(net "M_C_CPU0_SA_DQS_DN<0>")
	)
	(segment
		(start 335.45145 -285.166816)
		(end 335.44256 -285.171896)
		(width 0.088646)
		(layer "In4.Cu")
		(net "M_C_CPU0_SA_DQS_DN<0>")
	)
	(segment
		(start 339.484462 -277.522432)
		(end 339.452712 -277.638256)
		(width 0.088646)
		(layer "In4.Cu")
		(net "M_C_CPU0_SA_DQS_DN<0>")
	)
	(segment
		(start 316.121034 -309.361332)
		(end 315.732922 -309.749444)
		(width 0.18288)
		(layer "In4.Cu")
		(net "M_C_CPU0_SA_DQS_DN<0>")
	)
	(segment
		(start 319.54089 -304.201576)
		(end 319.54089 -306.117498)
		(width 0.18288)
		(layer "In4.Cu")
		(net "M_C_CPU0_SA_DQS_DN<0>")
	)
	(segment
		(start 337.80095 -281.097482)
		(end 337.79206 -281.102562)
		(width 0.088646)
		(layer "In4.Cu")
		(net "M_C_CPU0_SA_DQS_DN<0>")
	)
	(segment
		(start 298.811696 -314.19165)
		(end 298.563538 -314.439808)
		(width 0.18288)
		(layer "In4.Cu")
		(net "M_C_CPU0_SA_DQS_DN<0>")
	)
	(segment
		(start 318.588898 -307.06949)
		(end 318.20104 -307.457348)
		(width 0.18288)
		(layer "In4.Cu")
		(net "M_C_CPU0_SA_DQS_DN<0>")
	)
	(segment
		(start 291.864034 -313.653932)
		(end 289.491166 -313.653932)
		(width 0.18288)
		(layer "In4.Cu")
		(net "M_C_CPU0_SA_DQS_DN<0>")
	)
	(segment
		(start 322.164964 -301.577248)
		(end 321.988942 -301.577248)
		(width 0.18288)
		(layer "In4.Cu")
		(net "M_C_CPU0_SA_DQS_DN<0>")
	)
	(segment
		(start 282.93949 -312.746644)
		(end 282.321508 -312.128662)
		(width 0.18288)
		(layer "In4.Cu")
		(net "M_C_CPU0_SA_DQS_DN<0>")
	)
	(segment
		(start 293.49065 -314.821824)
		(end 292.707822 -314.497466)
		(width 0.18288)
		(layer "In4.Cu")
		(net "M_C_CPU0_SA_DQS_DN<0>")
	)
	(segment
		(start 284.388052 -312.76544)
		(end 284.11424 -312.491628)
		(width 0.18288)
		(layer "In4.Cu")
		(net "M_C_CPU0_SA_DQS_DN<0>")
	)
	(segment
		(start 332.859126 -285.763208)
		(end 332.420214 -286.20212)
		(width 0.18288)
		(layer "In4.Cu")
		(net "M_C_CPU0_SA_DQS_DN<0>")
	)
	(segment
		(start 284.11424 -312.491628)
		(end 283.722064 -312.491628)
		(width 0.18288)
		(layer "In4.Cu")
		(net "M_C_CPU0_SA_DQS_DN<0>")
	)
	(segment
		(start 317.249048 -308.40934)
		(end 317.073026 -308.40934)
		(width 0.18288)
		(layer "In4.Cu")
		(net "M_C_CPU0_SA_DQS_DN<0>")
	)
	(arc
		(start 337.979512 -279.160224)
		(mid 338.057623 -279.437173)
		(end 338.26196 -279.639776)
		(width 0.088646)
		(layer "In4.Cu")
		(net "M_C_CPU0_SA_DQS_DN<0>")
	)
	(arc
		(start 338.449412 -278.336502)
		(mid 338.401733 -278.519402)
		(end 338.27085 -278.65578)
		(width 0.088646)
		(layer "In4.Cu")
		(net "M_C_CPU0_SA_DQS_DN<0>")
	)
	(arc
		(start 337.79206 -281.102562)
		(mid 337.5853 -281.309325)
		(end 337.509612 -281.591766)
		(width 0.088646)
		(layer "In4.Cu")
		(net "M_C_CPU0_SA_DQS_DN<0>")
	)
	(arc
		(start 333.923894 -285.101792)
		(mid 333.737578 -285.106699)
		(end 333.56296 -285.171896)
		(width 0.088646)
		(layer "In4.Cu")
		(net "M_C_CPU0_SA_DQS_DN<0>")
	)
	(arc
		(start 338.26196 -280.288492)
		(mid 338.059674 -280.487473)
		(end 337.979512 -280.759662)
		(width 0.088646)
		(layer "In4.Cu")
		(net "M_C_CPU0_SA_DQS_DN<0>")
	)
	(arc
		(start 338.26196 -278.66086)
		(mid 338.057625 -278.863465)
		(end 337.979512 -279.140412)
		(width 0.088646)
		(layer "In4.Cu")
		(net "M_C_CPU0_SA_DQS_DN<0>")
	)
	(arc
		(start 338.27085 -279.644856)
		(mid 338.449447 -279.964134)
		(end 338.27085 -280.283412)
		(width 0.088646)
		(layer "In4.Cu")
		(net "M_C_CPU0_SA_DQS_DN<0>")
	)
	(arc
		(start 337.792314 -282.730194)
		(mid 337.605116 -282.780337)
		(end 337.417918 -282.730194)
		(width 0.088646)
		(layer "In4.Cu")
		(net "M_C_CPU0_SA_DQS_DN<0>")
	)
	(arc
		(start 336.376264 -283.54782)
		(mid 336.173851 -283.754233)
		(end 336.099912 -284.033722)
		(width 0.088646)
		(layer "In4.Cu")
		(net "M_C_CPU0_SA_DQS_DN<0>")
	)
	(arc
		(start 337.979512 -280.778204)
		(mid 337.931833 -280.961104)
		(end 337.80095 -281.097482)
		(width 0.088646)
		(layer "In4.Cu")
		(net "M_C_CPU0_SA_DQS_DN<0>")
	)
	(arc
		(start 337.509612 -281.59202)
		(mid 337.583603 -281.871586)
		(end 337.786218 -282.077922)
		(width 0.088646)
		(layer "In4.Cu")
		(net "M_C_CPU0_SA_DQS_DN<0>")
	)
	(arc
		(start 335.068164 -285.171896)
		(mid 334.785462 -285.09612)
		(end 334.50276 -285.171896)
		(width 0.088646)
		(layer "In4.Cu")
		(net "M_C_CPU0_SA_DQS_DN<0>")
	)
	(arc
		(start 335.91246 -284.35808)
		(mid 335.708125 -284.560685)
		(end 335.630012 -284.837632)
		(width 0.088646)
		(layer "In4.Cu")
		(net "M_C_CPU0_SA_DQS_DN<0>")
	)
	(arc
		(start 336.569812 -283.219906)
		(mid 336.522133 -283.402806)
		(end 336.39125 -283.539184)
		(width 0.088646)
		(layer "In4.Cu")
		(net "M_C_CPU0_SA_DQS_DN<0>")
	)
	(arc
		(start 336.099912 -284.033722)
		(mid 336.052233 -284.216622)
		(end 335.92135 -284.353)
		(width 0.088646)
		(layer "In4.Cu")
		(net "M_C_CPU0_SA_DQS_DN<0>")
	)
	(arc
		(start 337.979766 -282.405836)
		(mid 337.929473 -282.593012)
		(end 337.792314 -282.72994)
		(width 0.088646)
		(layer "In4.Cu")
		(net "M_C_CPU0_SA_DQS_DN<0>")
	)
	(arc
		(start 339.41385 -277.660354)
		(mid 339.357159 -277.687505)
		(end 339.297264 -277.706582)
		(width 0.088646)
		(layer "In4.Cu")
		(net "M_C_CPU0_SA_DQS_DN<0>")
	)
	(arc
		(start 334.50276 -285.171896)
		(mid 334.315562 -285.222039)
		(end 334.128364 -285.171896)
		(width 0.088646)
		(layer "In4.Cu")
		(net "M_C_CPU0_SA_DQS_DN<0>")
	)
	(arc
		(start 336.852514 -282.730194)
		(mid 336.649033 -282.930998)
		(end 336.569812 -283.205682)
		(width 0.088646)
		(layer "In4.Cu")
		(net "M_C_CPU0_SA_DQS_DN<0>")
	)
	(arc
		(start 339.19033 -277.719282)
		(mid 338.9516 -277.752224)
		(end 338.73059 -277.848314)
		(width 0.088646)
		(layer "In4.Cu")
		(net "M_C_CPU0_SA_DQS_DN<0>")
	)
	(arc
		(start 335.44256 -285.171896)
		(mid 335.255362 -285.222039)
		(end 335.068164 -285.171896)
		(width 0.088646)
		(layer "In4.Cu")
		(net "M_C_CPU0_SA_DQS_DN<0>")
	)
	(arc
		(start 335.630012 -284.847538)
		(mid 335.582333 -285.030438)
		(end 335.45145 -285.166816)
		(width 0.088646)
		(layer "In4.Cu")
		(net "M_C_CPU0_SA_DQS_DN<0>")
	)
	(arc
		(start 337.417918 -282.730194)
		(mid 337.143689 -282.654269)
		(end 336.867246 -282.721558)
		(width 0.088646)
		(layer "In4.Cu")
		(net "M_C_CPU0_SA_DQS_DN<0>")
	)
	(arc
		(start 338.732114 -277.84679)
		(mid 338.528633 -278.047594)
		(end 338.449412 -278.322278)
		(width 0.088646)
		(layer "In4.Cu")
		(net "M_C_CPU0_SA_DQS_DN<0>")
	)
	(arc
		(start 334.128364 -285.171896)
		(mid 334.029513 -285.126971)
		(end 333.923894 -285.101792)
		(width 0.088646)
		(layer "In4.Cu")
		(net "M_C_CPU0_SA_DQS_DN<0>")
	)
	(arc
		(start 337.792314 -282.081732)
		(mid 337.929454 -282.218671)
		(end 337.979766 -282.405836)
		(width 0.088646)
		(layer "In4.Cu")
		(net "M_C_CPU0_SA_DQS_DN<0>")
	)
	(arc
		(start 333.56296 -285.171896)
		(mid 333.502687 -285.211952)
		(end 333.448152 -285.259526)
		(width 0.088646)
		(layer "In4.Cu")
		(net "M_C_CPU0_SA_DQS_DN<0>")
	)
	(arc
		(start 339.297264 -277.706582)
		(mid 339.244175 -277.716113)
		(end 339.19033 -277.719282)
		(width 0.088646)
		(layer "In4.Cu")
		(net "M_C_CPU0_SA_DQS_DN<0>")
	)
	(segment
		(start 274.152868 -304.841656)
		(end 274.143978 -304.832766)
		(width 0.1016)
		(layer "F.Cu")
		(net "M_C_CPU0_SA_DQ<9>")
	)
	(segment
		(start 274.143978 -304.832766)
		(end 273.53514 -304.832766)
		(width 0.20066)
		(layer "F.Cu")
		(net "M_C_CPU0_SA_DQ<9>")
	)
	(segment
		(start 278.711914 -305.266598)
		(end 277.072598 -305.266598)
		(width 0.20066)
		(layer "F.Cu")
		(net "M_C_CPU0_SA_DQ<9>")
	)
	(segment
		(start 273.37258 -304.995326)
		(end 273.37258 -305.323494)
		(width 0.20066)
		(layer "F.Cu")
		(net "M_C_CPU0_SA_DQ<9>")
	)
	(segment
		(start 276.138386 -304.841656)
		(end 274.152868 -304.841656)
		(width 0.1016)
		(layer "F.Cu")
		(net "M_C_CPU0_SA_DQ<9>")
	)
	(segment
		(start 272.713704 -305.477926)
		(end 272.502376 -305.266598)
		(width 0.20066)
		(layer "F.Cu")
		(net "M_C_CPU0_SA_DQ<9>")
	)
	(segment
		(start 273.37258 -305.323494)
		(end 273.218148 -305.477926)
		(width 0.20066)
		(layer "F.Cu")
		(net "M_C_CPU0_SA_DQ<9>")
	)
	(segment
		(start 276.647656 -304.841656)
		(end 276.469094 -304.841656)
		(width 0.20066)
		(layer "F.Cu")
		(net "M_C_CPU0_SA_DQ<9>")
	)
	(segment
		(start 277.072598 -305.266598)
		(end 276.647656 -304.841656)
		(width 0.20066)
		(layer "F.Cu")
		(net "M_C_CPU0_SA_DQ<9>")
	)
	(segment
		(start 279.816814 -305.266598)
		(end 278.711914 -305.266598)
		(width 0.20066)
		(layer "F.Cu")
		(net "M_C_CPU0_SA_DQ<9>")
	)
	(segment
		(start 276.469094 -304.841656)
		(end 276.138386 -304.841656)
		(width 0.101854)
		(layer "F.Cu")
		(net "M_C_CPU0_SA_DQ<9>")
	)
	(segment
		(start 273.53514 -304.832766)
		(end 273.37258 -304.995326)
		(width 0.20066)
		(layer "F.Cu")
		(net "M_C_CPU0_SA_DQ<9>")
	)
	(segment
		(start 272.502376 -305.266598)
		(end 271.168114 -305.266598)
		(width 0.20066)
		(layer "F.Cu")
		(net "M_C_CPU0_SA_DQ<9>")
	)
	(segment
		(start 273.218148 -305.477926)
		(end 272.713704 -305.477926)
		(width 0.20066)
		(layer "F.Cu")
		(net "M_C_CPU0_SA_DQ<9>")
	)
	(arc
		(start 343.243916 -270.475456)
		(mid 343.243852 -270.743426)
		(end 343.243662 -271.011396)
		(width 0.20066)
		(layer "F.Cu")
		(net "M_C_CPU0_SA_DQ<9>")
	)
	(segment
		(start 290.870386 -302.422306)
		(end 287.032446 -304.011838)
		(width 0.18288)
		(layer "In6.Cu")
		(net "M_C_CPU0_SA_DQ<9>")
	)
	(segment
		(start 334.134714 -273.125184)
		(end 334.128618 -273.12874)
		(width 0.088646)
		(layer "In6.Cu")
		(net "M_C_CPU0_SA_DQ<9>")
	)
	(segment
		(start 297.491912 -296.341546)
		(end 296.641774 -297.191684)
		(width 0.18288)
		(layer "In6.Cu")
		(net "M_C_CPU0_SA_DQ<9>")
	)
	(segment
		(start 294.139112 -298.271692)
		(end 293.765732 -298.271692)
		(width 0.18288)
		(layer "In6.Cu")
		(net "M_C_CPU0_SA_DQ<9>")
	)
	(segment
		(start 285.35249 -305.691794)
		(end 280.24201 -305.691794)
		(width 0.18288)
		(layer "In6.Cu")
		(net "M_C_CPU0_SA_DQ<9>")
	)
	(segment
		(start 300.365414 -296.341546)
		(end 297.491912 -296.341546)
		(width 0.18288)
		(layer "In6.Cu")
		(net "M_C_CPU0_SA_DQ<9>")
	)
	(segment
		(start 312.088276 -290.393628)
		(end 309.773828 -290.393628)
		(width 0.18288)
		(layer "In6.Cu")
		(net "M_C_CPU0_SA_DQ<9>")
	)
	(segment
		(start 294.299132 -298.111672)
		(end 294.139112 -298.271692)
		(width 0.18288)
		(layer "In6.Cu")
		(net "M_C_CPU0_SA_DQ<9>")
	)
	(segment
		(start 303.58588 -293.12108)
		(end 300.365414 -296.341546)
		(width 0.18288)
		(layer "In6.Cu")
		(net "M_C_CPU0_SA_DQ<9>")
	)
	(segment
		(start 336.392774 -271.50695)
		(end 336.38236 -271.500854)
		(width 0.088646)
		(layer "In6.Cu")
		(net "M_C_CPU0_SA_DQ<9>")
	)
	(segment
		(start 333.084678 -273.76628)
		(end 331.633322 -275.217636)
		(width 0.088646)
		(layer "In6.Cu")
		(net "M_C_CPU0_SA_DQ<9>")
	)
	(segment
		(start 292.11397 -298.101258)
		(end 292.11397 -301.178722)
		(width 0.18288)
		(layer "In6.Cu")
		(net "M_C_CPU0_SA_DQ<9>")
	)
	(segment
		(start 342.675718 -271.448276)
		(end 342.586818 -271.500854)
		(width 0.088646)
		(layer "In6.Cu")
		(net "M_C_CPU0_SA_DQ<9>")
	)
	(segment
		(start 293.445692 -297.191684)
		(end 293.023544 -297.191684)
		(width 0.18288)
		(layer "In6.Cu")
		(net "M_C_CPU0_SA_DQ<9>")
	)
	(segment
		(start 337.332828 -271.50695)
		(end 337.322414 -271.500854)
		(width 0.088646)
		(layer "In6.Cu")
		(net "M_C_CPU0_SA_DQ<9>")
	)
	(segment
		(start 335.820512 -271.825212)
		(end 335.820512 -271.843754)
		(width 0.088646)
		(layer "In6.Cu")
		(net "M_C_CPU0_SA_DQ<9>")
	)
	(segment
		(start 334.598518 -272.314924)
		(end 334.589628 -272.320004)
		(width 0.088646)
		(layer "In6.Cu")
		(net "M_C_CPU0_SA_DQ<9>")
	)
	(segment
		(start 333.117698 -273.25193)
		(end 333.117698 -273.686524)
		(width 0.088646)
		(layer "In6.Cu")
		(net "M_C_CPU0_SA_DQ<9>")
	)
	(segment
		(start 331.633322 -275.217636)
		(end 331.283056 -275.217636)
		(width 0.088646)
		(layer "In6.Cu")
		(net "M_C_CPU0_SA_DQ<9>")
	)
	(segment
		(start 280.24201 -305.691794)
		(end 279.816814 -305.266598)
		(width 0.18288)
		(layer "In6.Cu")
		(net "M_C_CPU0_SA_DQ<9>")
	)
	(segment
		(start 333.577946 -273.137376)
		(end 333.563214 -273.12874)
		(width 0.088646)
		(layer "In6.Cu")
		(net "M_C_CPU0_SA_DQ<9>")
	)
	(segment
		(start 341.096346 -271.50949)
		(end 341.081614 -271.500854)
		(width 0.088646)
		(layer "In6.Cu")
		(net "M_C_CPU0_SA_DQ<9>")
	)
	(segment
		(start 293.023544 -297.191684)
		(end 292.11397 -298.101258)
		(width 0.18288)
		(layer "In6.Cu")
		(net "M_C_CPU0_SA_DQ<9>")
	)
	(segment
		(start 293.605712 -297.351704)
		(end 293.445692 -297.191684)
		(width 0.18288)
		(layer "In6.Cu")
		(net "M_C_CPU0_SA_DQ<9>")
	)
	(segment
		(start 294.459152 -297.191684)
		(end 294.299132 -297.351704)
		(width 0.18288)
		(layer "In6.Cu")
		(net "M_C_CPU0_SA_DQ<9>")
	)
	(segment
		(start 293.605712 -298.111672)
		(end 293.605712 -297.351704)
		(width 0.18288)
		(layer "In6.Cu")
		(net "M_C_CPU0_SA_DQ<9>")
	)
	(segment
		(start 334.983328 -272.32102)
		(end 334.972914 -272.314924)
		(width 0.088646)
		(layer "In6.Cu")
		(net "M_C_CPU0_SA_DQ<9>")
	)
	(segment
		(start 292.11397 -301.178722)
		(end 290.870386 -302.422306)
		(width 0.18288)
		(layer "In6.Cu")
		(net "M_C_CPU0_SA_DQ<9>")
	)
	(segment
		(start 308.92623 -291.241226)
		(end 306.309014 -291.241226)
		(width 0.18288)
		(layer "In6.Cu")
		(net "M_C_CPU0_SA_DQ<9>")
	)
	(segment
		(start 336.007964 -271.500854)
		(end 335.999074 -271.505934)
		(width 0.088646)
		(layer "In6.Cu")
		(net "M_C_CPU0_SA_DQ<9>")
	)
	(segment
		(start 340.156546 -271.50949)
		(end 340.141814 -271.500854)
		(width 0.088646)
		(layer "In6.Cu")
		(net "M_C_CPU0_SA_DQ<9>")
	)
	(segment
		(start 330.832206 -275.217636)
		(end 326.540622 -276.995382)
		(width 0.18288)
		(layer "In6.Cu")
		(net "M_C_CPU0_SA_DQ<9>")
	)
	(segment
		(start 339.212174 -271.50695)
		(end 339.20176 -271.500854)
		(width 0.088646)
		(layer "In6.Cu")
		(net "M_C_CPU0_SA_DQ<9>")
	)
	(segment
		(start 287.032446 -304.011838)
		(end 285.35249 -305.691794)
		(width 0.18288)
		(layer "In6.Cu")
		(net "M_C_CPU0_SA_DQ<9>")
	)
	(segment
		(start 296.641774 -297.191684)
		(end 294.459152 -297.191684)
		(width 0.18288)
		(layer "In6.Cu")
		(net "M_C_CPU0_SA_DQ<9>")
	)
	(segment
		(start 294.299132 -297.351704)
		(end 294.299132 -298.111672)
		(width 0.18288)
		(layer "In6.Cu")
		(net "M_C_CPU0_SA_DQ<9>")
	)
	(segment
		(start 293.765732 -298.271692)
		(end 293.605712 -298.111672)
		(width 0.18288)
		(layer "In6.Cu")
		(net "M_C_CPU0_SA_DQ<9>")
	)
	(segment
		(start 304.42916 -293.12108)
		(end 303.58588 -293.12108)
		(width 0.18288)
		(layer "In6.Cu")
		(net "M_C_CPU0_SA_DQ<9>")
	)
	(segment
		(start 309.773828 -290.393628)
		(end 308.92623 -291.241226)
		(width 0.18288)
		(layer "In6.Cu")
		(net "M_C_CPU0_SA_DQ<9>")
	)
	(segment
		(start 326.540622 -276.995382)
		(end 314.799218 -288.736786)
		(width 0.18288)
		(layer "In6.Cu")
		(net "M_C_CPU0_SA_DQ<9>")
	)
	(segment
		(start 314.799218 -288.736786)
		(end 313.745118 -288.736786)
		(width 0.18288)
		(layer "In6.Cu")
		(net "M_C_CPU0_SA_DQ<9>")
	)
	(segment
		(start 313.745118 -288.736786)
		(end 312.088276 -290.393628)
		(width 0.18288)
		(layer "In6.Cu")
		(net "M_C_CPU0_SA_DQ<9>")
	)
	(segment
		(start 306.309014 -291.241226)
		(end 304.42916 -293.12108)
		(width 0.18288)
		(layer "In6.Cu")
		(net "M_C_CPU0_SA_DQ<9>")
	)
	(segment
		(start 343.243662 -271.011396)
		(end 342.675718 -271.448276)
		(width 0.088646)
		(layer "In6.Cu")
		(net "M_C_CPU0_SA_DQ<9>")
	)
	(segment
		(start 331.283056 -275.217636)
		(end 330.832206 -275.217636)
		(width 0.18288)
		(layer "In6.Cu")
		(net "M_C_CPU0_SA_DQ<9>")
	)
	(arc
		(start 335.538064 -272.314924)
		(mid 335.261505 -272.390633)
		(end 334.983328 -272.32102)
		(width 0.088646)
		(layer "In6.Cu")
		(net "M_C_CPU0_SA_DQ<9>")
	)
	(arc
		(start 338.26196 -271.500854)
		(mid 338.074762 -271.450711)
		(end 337.887564 -271.500854)
		(width 0.088646)
		(layer "In6.Cu")
		(net "M_C_CPU0_SA_DQ<9>")
	)
	(arc
		(start 341.647018 -271.500854)
		(mid 341.372819 -271.576689)
		(end 341.096346 -271.50949)
		(width 0.088646)
		(layer "In6.Cu")
		(net "M_C_CPU0_SA_DQ<9>")
	)
	(arc
		(start 336.948018 -271.500854)
		(mid 336.671205 -271.576724)
		(end 336.392774 -271.50695)
		(width 0.088646)
		(layer "In6.Cu")
		(net "M_C_CPU0_SA_DQ<9>")
	)
	(arc
		(start 335.820512 -271.843754)
		(mid 335.74035 -272.115943)
		(end 335.538064 -272.314924)
		(width 0.088646)
		(layer "In6.Cu")
		(net "M_C_CPU0_SA_DQ<9>")
	)
	(arc
		(start 342.021414 -271.500854)
		(mid 341.834216 -271.450711)
		(end 341.647018 -271.500854)
		(width 0.088646)
		(layer "In6.Cu")
		(net "M_C_CPU0_SA_DQ<9>")
	)
	(arc
		(start 334.589628 -272.320004)
		(mid 334.458714 -272.456364)
		(end 334.411066 -272.639282)
		(width 0.088646)
		(layer "In6.Cu")
		(net "M_C_CPU0_SA_DQ<9>")
	)
	(arc
		(start 340.141814 -271.500854)
		(mid 339.954616 -271.450711)
		(end 339.767418 -271.500854)
		(width 0.088646)
		(layer "In6.Cu")
		(net "M_C_CPU0_SA_DQ<9>")
	)
	(arc
		(start 341.081614 -271.500854)
		(mid 340.894416 -271.450711)
		(end 340.707218 -271.500854)
		(width 0.088646)
		(layer "In6.Cu")
		(net "M_C_CPU0_SA_DQ<9>")
	)
	(arc
		(start 339.767418 -271.500854)
		(mid 339.490605 -271.576724)
		(end 339.212174 -271.50695)
		(width 0.088646)
		(layer "In6.Cu")
		(net "M_C_CPU0_SA_DQ<9>")
	)
	(arc
		(start 337.887564 -271.500854)
		(mid 337.611005 -271.576597)
		(end 337.332828 -271.50695)
		(width 0.088646)
		(layer "In6.Cu")
		(net "M_C_CPU0_SA_DQ<9>")
	)
	(arc
		(start 334.128618 -273.12874)
		(mid 333.854419 -273.204575)
		(end 333.577946 -273.137376)
		(width 0.088646)
		(layer "In6.Cu")
		(net "M_C_CPU0_SA_DQ<9>")
	)
	(arc
		(start 333.188818 -273.12874)
		(mid 333.13675 -273.180806)
		(end 333.117698 -273.25193)
		(width 0.088646)
		(layer "In6.Cu")
		(net "M_C_CPU0_SA_DQ<9>")
	)
	(arc
		(start 336.38236 -271.500854)
		(mid 336.195162 -271.450711)
		(end 336.007964 -271.500854)
		(width 0.088646)
		(layer "In6.Cu")
		(net "M_C_CPU0_SA_DQ<9>")
	)
	(arc
		(start 337.322414 -271.500854)
		(mid 337.135216 -271.450711)
		(end 336.948018 -271.500854)
		(width 0.088646)
		(layer "In6.Cu")
		(net "M_C_CPU0_SA_DQ<9>")
	)
	(arc
		(start 339.20176 -271.500854)
		(mid 339.014562 -271.450711)
		(end 338.827364 -271.500854)
		(width 0.088646)
		(layer "In6.Cu")
		(net "M_C_CPU0_SA_DQ<9>")
	)
	(arc
		(start 342.586818 -271.500854)
		(mid 342.304116 -271.57663)
		(end 342.021414 -271.500854)
		(width 0.088646)
		(layer "In6.Cu")
		(net "M_C_CPU0_SA_DQ<9>")
	)
	(arc
		(start 334.972914 -272.314924)
		(mid 334.785716 -272.264781)
		(end 334.598518 -272.314924)
		(width 0.088646)
		(layer "In6.Cu")
		(net "M_C_CPU0_SA_DQ<9>")
	)
	(arc
		(start 340.707218 -271.500854)
		(mid 340.433019 -271.576689)
		(end 340.156546 -271.50949)
		(width 0.088646)
		(layer "In6.Cu")
		(net "M_C_CPU0_SA_DQ<9>")
	)
	(arc
		(start 333.117698 -273.686524)
		(mid 333.109113 -273.729682)
		(end 333.084678 -273.76628)
		(width 0.088646)
		(layer "In6.Cu")
		(net "M_C_CPU0_SA_DQ<9>")
	)
	(arc
		(start 334.411066 -272.639282)
		(mid 334.33715 -272.918784)
		(end 334.134714 -273.125184)
		(width 0.088646)
		(layer "In6.Cu")
		(net "M_C_CPU0_SA_DQ<9>")
	)
	(arc
		(start 335.999074 -271.505934)
		(mid 335.86816 -271.642294)
		(end 335.820512 -271.825212)
		(width 0.088646)
		(layer "In6.Cu")
		(net "M_C_CPU0_SA_DQ<9>")
	)
	(arc
		(start 338.827364 -271.500854)
		(mid 338.544662 -271.57663)
		(end 338.26196 -271.500854)
		(width 0.088646)
		(layer "In6.Cu")
		(net "M_C_CPU0_SA_DQ<9>")
	)
	(arc
		(start 333.563214 -273.12874)
		(mid 333.376016 -273.078597)
		(end 333.188818 -273.12874)
		(width 0.088646)
		(layer "In6.Cu")
		(net "M_C_CPU0_SA_DQ<9>")
	)
	(segment
		(start 272.741136 -307.20538)
		(end 272.502376 -306.96662)
		(width 0.20066)
		(layer "F.Cu")
		(net "M_C_CPU0_SA_DQ<8>")
	)
	(segment
		(start 274.40001 -306.541678)
		(end 274.152106 -306.541678)
		(width 0.101854)
		(layer "F.Cu")
		(net "M_C_CPU0_SA_DQ<8>")
	)
	(segment
		(start 278.711914 -306.96662)
		(end 277.342854 -306.96662)
		(width 0.20066)
		(layer "F.Cu")
		(net "M_C_CPU0_SA_DQ<8>")
	)
	(segment
		(start 273.37258 -307.03266)
		(end 273.19986 -307.20538)
		(width 0.20066)
		(layer "F.Cu")
		(net "M_C_CPU0_SA_DQ<8>")
	)
	(segment
		(start 274.152106 -306.541678)
		(end 274.143978 -306.53355)
		(width 0.101854)
		(layer "F.Cu")
		(net "M_C_CPU0_SA_DQ<8>")
	)
	(segment
		(start 273.58213 -306.53355)
		(end 273.37258 -306.7431)
		(width 0.20066)
		(layer "F.Cu")
		(net "M_C_CPU0_SA_DQ<8>")
	)
	(segment
		(start 343.713816 -271.289526)
		(end 343.713816 -271.825212)
		(width 0.20066)
		(layer "F.Cu")
		(net "M_C_CPU0_SA_DQ<8>")
	)
	(segment
		(start 274.143978 -306.53355)
		(end 273.58213 -306.53355)
		(width 0.20066)
		(layer "F.Cu")
		(net "M_C_CPU0_SA_DQ<8>")
	)
	(segment
		(start 276.469094 -306.541678)
		(end 274.40001 -306.541678)
		(width 0.1016)
		(layer "F.Cu")
		(net "M_C_CPU0_SA_DQ<8>")
	)
	(segment
		(start 272.502376 -306.96662)
		(end 271.168114 -306.96662)
		(width 0.20066)
		(layer "F.Cu")
		(net "M_C_CPU0_SA_DQ<8>")
	)
	(segment
		(start 343.713562 -271.289272)
		(end 343.713816 -271.289526)
		(width 0.20066)
		(layer "F.Cu")
		(net "M_C_CPU0_SA_DQ<8>")
	)
	(segment
		(start 276.917912 -306.541678)
		(end 276.469094 -306.541678)
		(width 0.20066)
		(layer "F.Cu")
		(net "M_C_CPU0_SA_DQ<8>")
	)
	(segment
		(start 273.37258 -306.7431)
		(end 273.37258 -307.03266)
		(width 0.20066)
		(layer "F.Cu")
		(net "M_C_CPU0_SA_DQ<8>")
	)
	(segment
		(start 273.19986 -307.20538)
		(end 272.741136 -307.20538)
		(width 0.20066)
		(layer "F.Cu")
		(net "M_C_CPU0_SA_DQ<8>")
	)
	(segment
		(start 279.816814 -306.96662)
		(end 278.711914 -306.96662)
		(width 0.20066)
		(layer "F.Cu")
		(net "M_C_CPU0_SA_DQ<8>")
	)
	(segment
		(start 277.342854 -306.96662)
		(end 276.917912 -306.541678)
		(width 0.20066)
		(layer "F.Cu")
		(net "M_C_CPU0_SA_DQ<8>")
	)
	(segment
		(start 331.283056 -276.261068)
		(end 330.98867 -276.261068)
		(width 0.18288)
		(layer "In6.Cu")
		(net "M_C_CPU0_SA_DQ<8>")
	)
	(segment
		(start 333.58074 -274.001992)
		(end 333.449676 -274.133056)
		(width 0.088646)
		(layer "In6.Cu")
		(net "M_C_CPU0_SA_DQ<8>")
	)
	(segment
		(start 308.864254 -292.451536)
		(end 308.536594 -292.451536)
		(width 0.18288)
		(layer "In6.Cu")
		(net "M_C_CPU0_SA_DQ<8>")
	)
	(segment
		(start 334.598264 -273.942556)
		(end 334.583532 -273.951192)
		(width 0.088646)
		(layer "In6.Cu")
		(net "M_C_CPU0_SA_DQ<8>")
	)
	(segment
		(start 289.07867 -304.764948)
		(end 288.295334 -305.548284)
		(width 0.18288)
		(layer "In6.Cu")
		(net "M_C_CPU0_SA_DQ<8>")
	)
	(segment
		(start 291.21354 -304.764948)
		(end 289.07867 -304.764948)
		(width 0.18288)
		(layer "In6.Cu")
		(net "M_C_CPU0_SA_DQ<8>")
	)
	(segment
		(start 312.032142 -292.141402)
		(end 311.174384 -292.141402)
		(width 0.18288)
		(layer "In6.Cu")
		(net "M_C_CPU0_SA_DQ<8>")
	)
	(segment
		(start 294.47744 -299.74159)
		(end 293.88308 -300.33595)
		(width 0.18288)
		(layer "In6.Cu")
		(net "M_C_CPU0_SA_DQ<8>")
	)
	(segment
		(start 327.492868 -277.709122)
		(end 314.767976 -290.434014)
		(width 0.18288)
		(layer "In6.Cu")
		(net "M_C_CPU0_SA_DQ<8>")
	)
	(segment
		(start 308.353714 -292.789356)
		(end 308.170834 -292.972236)
		(width 0.18288)
		(layer "In6.Cu")
		(net "M_C_CPU0_SA_DQ<8>")
	)
	(segment
		(start 282.644342 -306.372006)
		(end 280.411428 -306.372006)
		(width 0.18288)
		(layer "In6.Cu")
		(net "M_C_CPU0_SA_DQ<8>")
	)
	(segment
		(start 280.411428 -306.372006)
		(end 279.816814 -306.96662)
		(width 0.18288)
		(layer "In6.Cu")
		(net "M_C_CPU0_SA_DQ<8>")
	)
	(segment
		(start 337.802474 -272.32102)
		(end 337.79206 -272.314924)
		(width 0.088646)
		(layer "In6.Cu")
		(net "M_C_CPU0_SA_DQ<8>")
	)
	(segment
		(start 308.536594 -292.451536)
		(end 308.353714 -292.634416)
		(width 0.18288)
		(layer "In6.Cu")
		(net "M_C_CPU0_SA_DQ<8>")
	)
	(segment
		(start 311.174384 -292.141402)
		(end 310.34355 -292.972236)
		(width 0.18288)
		(layer "In6.Cu")
		(net "M_C_CPU0_SA_DQ<8>")
	)
	(segment
		(start 309.047134 -292.789356)
		(end 309.047134 -292.634416)
		(width 0.18288)
		(layer "In6.Cu")
		(net "M_C_CPU0_SA_DQ<8>")
	)
	(segment
		(start 283.660596 -307.38826)
		(end 282.644342 -306.372006)
		(width 0.18288)
		(layer "In6.Cu")
		(net "M_C_CPU0_SA_DQ<8>")
	)
	(segment
		(start 308.170834 -292.972236)
		(end 307.160422 -292.972236)
		(width 0.18288)
		(layer "In6.Cu")
		(net "M_C_CPU0_SA_DQ<8>")
	)
	(segment
		(start 343.08542 -272.298414)
		(end 343.056464 -272.314924)
		(width 0.088646)
		(layer "In6.Cu")
		(net "M_C_CPU0_SA_DQ<8>")
	)
	(segment
		(start 293.88308 -302.095408)
		(end 291.21354 -304.764948)
		(width 0.18288)
		(layer "In6.Cu")
		(net "M_C_CPU0_SA_DQ<8>")
	)
	(segment
		(start 343.056464 -272.314924)
		(end 343.041732 -272.32356)
		(width 0.088646)
		(layer "In6.Cu")
		(net "M_C_CPU0_SA_DQ<8>")
	)
	(segment
		(start 304.00752 -295.141396)
		(end 303.235106 -295.91381)
		(width 0.18288)
		(layer "In6.Cu")
		(net "M_C_CPU0_SA_DQ<8>")
	)
	(segment
		(start 334.60436 -273.939)
		(end 334.598264 -273.942556)
		(width 0.088646)
		(layer "In6.Cu")
		(net "M_C_CPU0_SA_DQ<8>")
	)
	(segment
		(start 340.237064 -272.314924)
		(end 340.222332 -272.32356)
		(width 0.088646)
		(layer "In6.Cu")
		(net "M_C_CPU0_SA_DQ<8>")
	)
	(segment
		(start 337.417664 -272.314924)
		(end 337.40725 -272.32102)
		(width 0.088646)
		(layer "In6.Cu")
		(net "M_C_CPU0_SA_DQ<8>")
	)
	(segment
		(start 308.353714 -292.634416)
		(end 308.353714 -292.789356)
		(width 0.18288)
		(layer "In6.Cu")
		(net "M_C_CPU0_SA_DQ<8>")
	)
	(segment
		(start 343.42324 -272.223992)
		(end 343.238582 -272.24228)
		(width 0.088646)
		(layer "In6.Cu")
		(net "M_C_CPU0_SA_DQ<8>")
	)
	(segment
		(start 332.788006 -275.114004)
		(end 332.58252 -275.114004)
		(width 0.088646)
		(layer "In6.Cu")
		(net "M_C_CPU0_SA_DQ<8>")
	)
	(segment
		(start 293.88308 -300.33595)
		(end 293.88308 -302.095408)
		(width 0.18288)
		(layer "In6.Cu")
		(net "M_C_CPU0_SA_DQ<8>")
	)
	(segment
		(start 302.063658 -298.041568)
		(end 298.83481 -298.041568)
		(width 0.18288)
		(layer "In6.Cu")
		(net "M_C_CPU0_SA_DQ<8>")
	)
	(segment
		(start 332.58252 -275.114004)
		(end 331.435456 -276.261068)
		(width 0.088646)
		(layer "In6.Cu")
		(net "M_C_CPU0_SA_DQ<8>")
	)
	(segment
		(start 304.991262 -295.141396)
		(end 304.00752 -295.141396)
		(width 0.18288)
		(layer "In6.Cu")
		(net "M_C_CPU0_SA_DQ<8>")
	)
	(segment
		(start 303.235106 -296.87012)
		(end 302.063658 -298.041568)
		(width 0.18288)
		(layer "In6.Cu")
		(net "M_C_CPU0_SA_DQ<8>")
	)
	(segment
		(start 309.230014 -292.972236)
		(end 309.047134 -292.789356)
		(width 0.18288)
		(layer "In6.Cu")
		(net "M_C_CPU0_SA_DQ<8>")
	)
	(segment
		(start 336.020156 -273.121628)
		(end 336.007964 -273.12874)
		(width 0.088646)
		(layer "In6.Cu")
		(net "M_C_CPU0_SA_DQ<8>")
	)
	(segment
		(start 330.98867 -276.261068)
		(end 327.492868 -277.709122)
		(width 0.18288)
		(layer "In6.Cu")
		(net "M_C_CPU0_SA_DQ<8>")
	)
	(segment
		(start 310.34355 -292.972236)
		(end 309.230014 -292.972236)
		(width 0.18288)
		(layer "In6.Cu")
		(net "M_C_CPU0_SA_DQ<8>")
	)
	(segment
		(start 338.742528 -272.32102)
		(end 338.732114 -272.314924)
		(width 0.088646)
		(layer "In6.Cu")
		(net "M_C_CPU0_SA_DQ<8>")
	)
	(segment
		(start 303.235106 -295.91381)
		(end 303.235106 -296.87012)
		(width 0.18288)
		(layer "In6.Cu")
		(net "M_C_CPU0_SA_DQ<8>")
	)
	(segment
		(start 342.116664 -272.314924)
		(end 342.101932 -272.32356)
		(width 0.088646)
		(layer "In6.Cu")
		(net "M_C_CPU0_SA_DQ<8>")
	)
	(segment
		(start 284.349444 -307.146452)
		(end 284.107636 -307.38826)
		(width 0.18288)
		(layer "In6.Cu")
		(net "M_C_CPU0_SA_DQ<8>")
	)
	(segment
		(start 297.134788 -299.74159)
		(end 294.47744 -299.74159)
		(width 0.18288)
		(layer "In6.Cu")
		(net "M_C_CPU0_SA_DQ<8>")
	)
	(segment
		(start 307.160422 -292.972236)
		(end 304.991262 -295.141396)
		(width 0.18288)
		(layer "In6.Cu")
		(net "M_C_CPU0_SA_DQ<8>")
	)
	(segment
		(start 341.176864 -272.314924)
		(end 341.162132 -272.32356)
		(width 0.088646)
		(layer "In6.Cu")
		(net "M_C_CPU0_SA_DQ<8>")
	)
	(segment
		(start 298.83481 -298.041568)
		(end 297.134788 -299.74159)
		(width 0.18288)
		(layer "In6.Cu")
		(net "M_C_CPU0_SA_DQ<8>")
	)
	(segment
		(start 343.15273 -272.266156)
		(end 343.08542 -272.298414)
		(width 0.088646)
		(layer "In6.Cu")
		(net "M_C_CPU0_SA_DQ<8>")
	)
	(segment
		(start 333.449676 -274.452334)
		(end 332.788006 -275.114004)
		(width 0.088646)
		(layer "In6.Cu")
		(net "M_C_CPU0_SA_DQ<8>")
	)
	(segment
		(start 314.767976 -290.434014)
		(end 313.73953 -290.434014)
		(width 0.18288)
		(layer "In6.Cu")
		(net "M_C_CPU0_SA_DQ<8>")
	)
	(segment
		(start 336.478118 -272.314924)
		(end 336.469228 -272.320004)
		(width 0.088646)
		(layer "In6.Cu")
		(net "M_C_CPU0_SA_DQ<8>")
	)
	(segment
		(start 284.107636 -307.38826)
		(end 283.660596 -307.38826)
		(width 0.18288)
		(layer "In6.Cu")
		(net "M_C_CPU0_SA_DQ<8>")
	)
	(segment
		(start 333.449676 -274.133056)
		(end 333.449676 -274.452334)
		(width 0.088646)
		(layer "In6.Cu")
		(net "M_C_CPU0_SA_DQ<8>")
	)
	(segment
		(start 313.73953 -290.434014)
		(end 312.032142 -292.141402)
		(width 0.18288)
		(layer "In6.Cu")
		(net "M_C_CPU0_SA_DQ<8>")
	)
	(segment
		(start 343.511124 -272.19275)
		(end 343.507568 -272.195036)
		(width 0.088646)
		(layer "In6.Cu")
		(net "M_C_CPU0_SA_DQ<8>")
	)
	(segment
		(start 331.435456 -276.261068)
		(end 331.283056 -276.261068)
		(width 0.088646)
		(layer "In6.Cu")
		(net "M_C_CPU0_SA_DQ<8>")
	)
	(segment
		(start 288.295334 -305.548284)
		(end 287.214056 -305.548284)
		(width 0.18288)
		(layer "In6.Cu")
		(net "M_C_CPU0_SA_DQ<8>")
	)
	(segment
		(start 285.615888 -307.146452)
		(end 284.349444 -307.146452)
		(width 0.18288)
		(layer "In6.Cu")
		(net "M_C_CPU0_SA_DQ<8>")
	)
	(segment
		(start 334.880966 -273.444462)
		(end 334.880966 -273.453098)
		(width 0.088646)
		(layer "In6.Cu")
		(net "M_C_CPU0_SA_DQ<8>")
	)
	(segment
		(start 309.047134 -292.634416)
		(end 308.864254 -292.451536)
		(width 0.18288)
		(layer "In6.Cu")
		(net "M_C_CPU0_SA_DQ<8>")
	)
	(segment
		(start 287.214056 -305.548284)
		(end 285.615888 -307.146452)
		(width 0.18288)
		(layer "In6.Cu")
		(net "M_C_CPU0_SA_DQ<8>")
	)
	(arc
		(start 335.44256 -273.12874)
		(mid 335.255362 -273.078597)
		(end 335.068164 -273.12874)
		(width 0.088646)
		(layer "In6.Cu")
		(net "M_C_CPU0_SA_DQ<8>")
	)
	(arc
		(start 343.238582 -272.24228)
		(mid 343.194627 -272.250516)
		(end 343.15273 -272.266156)
		(width 0.088646)
		(layer "In6.Cu")
		(net "M_C_CPU0_SA_DQ<8>")
	)
	(arc
		(start 343.713816 -271.825212)
		(mid 343.659839 -272.035103)
		(end 343.511124 -272.19275)
		(width 0.088646)
		(layer "In6.Cu")
		(net "M_C_CPU0_SA_DQ<8>")
	)
	(arc
		(start 336.007964 -273.12874)
		(mid 335.725262 -273.204516)
		(end 335.44256 -273.12874)
		(width 0.088646)
		(layer "In6.Cu")
		(net "M_C_CPU0_SA_DQ<8>")
	)
	(arc
		(start 334.03286 -273.942556)
		(mid 333.845662 -273.892413)
		(end 333.658464 -273.942556)
		(width 0.088646)
		(layer "In6.Cu")
		(net "M_C_CPU0_SA_DQ<8>")
	)
	(arc
		(start 341.55126 -272.314924)
		(mid 341.364062 -272.264781)
		(end 341.176864 -272.314924)
		(width 0.088646)
		(layer "In6.Cu")
		(net "M_C_CPU0_SA_DQ<8>")
	)
	(arc
		(start 337.40725 -272.32102)
		(mid 337.129072 -272.390712)
		(end 336.852514 -272.314924)
		(width 0.088646)
		(layer "In6.Cu")
		(net "M_C_CPU0_SA_DQ<8>")
	)
	(arc
		(start 339.67166 -272.314924)
		(mid 339.484462 -272.264781)
		(end 339.297264 -272.314924)
		(width 0.088646)
		(layer "In6.Cu")
		(net "M_C_CPU0_SA_DQ<8>")
	)
	(arc
		(start 343.507568 -272.195036)
		(mid 343.467086 -272.214404)
		(end 343.42324 -272.223992)
		(width 0.088646)
		(layer "In6.Cu")
		(net "M_C_CPU0_SA_DQ<8>")
	)
	(arc
		(start 334.880966 -273.453098)
		(mid 334.806975 -273.732664)
		(end 334.60436 -273.939)
		(width 0.088646)
		(layer "In6.Cu")
		(net "M_C_CPU0_SA_DQ<8>")
	)
	(arc
		(start 343.041732 -272.32356)
		(mid 342.765291 -272.390726)
		(end 342.49106 -272.314924)
		(width 0.088646)
		(layer "In6.Cu")
		(net "M_C_CPU0_SA_DQ<8>")
	)
	(arc
		(start 341.162132 -272.32356)
		(mid 340.885691 -272.390726)
		(end 340.61146 -272.314924)
		(width 0.088646)
		(layer "In6.Cu")
		(net "M_C_CPU0_SA_DQ<8>")
	)
	(arc
		(start 338.357718 -272.314924)
		(mid 338.080905 -272.39076)
		(end 337.802474 -272.32102)
		(width 0.088646)
		(layer "In6.Cu")
		(net "M_C_CPU0_SA_DQ<8>")
	)
	(arc
		(start 336.469228 -272.320004)
		(mid 336.338314 -272.456364)
		(end 336.290666 -272.639282)
		(width 0.088646)
		(layer "In6.Cu")
		(net "M_C_CPU0_SA_DQ<8>")
	)
	(arc
		(start 333.658464 -273.942556)
		(mid 333.617655 -273.969728)
		(end 333.58074 -274.001992)
		(width 0.088646)
		(layer "In6.Cu")
		(net "M_C_CPU0_SA_DQ<8>")
	)
	(arc
		(start 342.49106 -272.314924)
		(mid 342.303862 -272.264781)
		(end 342.116664 -272.314924)
		(width 0.088646)
		(layer "In6.Cu")
		(net "M_C_CPU0_SA_DQ<8>")
	)
	(arc
		(start 337.79206 -272.314924)
		(mid 337.604862 -272.264781)
		(end 337.417664 -272.314924)
		(width 0.088646)
		(layer "In6.Cu")
		(net "M_C_CPU0_SA_DQ<8>")
	)
	(arc
		(start 334.583532 -273.951192)
		(mid 334.307057 -274.018512)
		(end 334.03286 -273.942556)
		(width 0.088646)
		(layer "In6.Cu")
		(net "M_C_CPU0_SA_DQ<8>")
	)
	(arc
		(start 340.61146 -272.314924)
		(mid 340.424262 -272.264781)
		(end 340.237064 -272.314924)
		(width 0.088646)
		(layer "In6.Cu")
		(net "M_C_CPU0_SA_DQ<8>")
	)
	(arc
		(start 336.290666 -272.639282)
		(mid 336.218431 -272.915806)
		(end 336.020156 -273.121628)
		(width 0.088646)
		(layer "In6.Cu")
		(net "M_C_CPU0_SA_DQ<8>")
	)
	(arc
		(start 339.297264 -272.314924)
		(mid 339.020705 -272.390633)
		(end 338.742528 -272.32102)
		(width 0.088646)
		(layer "In6.Cu")
		(net "M_C_CPU0_SA_DQ<8>")
	)
	(arc
		(start 342.101932 -272.32356)
		(mid 341.825491 -272.390726)
		(end 341.55126 -272.314924)
		(width 0.088646)
		(layer "In6.Cu")
		(net "M_C_CPU0_SA_DQ<8>")
	)
	(arc
		(start 336.852514 -272.314924)
		(mid 336.665316 -272.264781)
		(end 336.478118 -272.314924)
		(width 0.088646)
		(layer "In6.Cu")
		(net "M_C_CPU0_SA_DQ<8>")
	)
	(arc
		(start 335.068164 -273.12874)
		(mid 334.933231 -273.262094)
		(end 334.880966 -273.444462)
		(width 0.088646)
		(layer "In6.Cu")
		(net "M_C_CPU0_SA_DQ<8>")
	)
	(arc
		(start 340.222332 -272.32356)
		(mid 339.945891 -272.390726)
		(end 339.67166 -272.314924)
		(width 0.088646)
		(layer "In6.Cu")
		(net "M_C_CPU0_SA_DQ<8>")
	)
	(arc
		(start 338.732114 -272.314924)
		(mid 338.544916 -272.264781)
		(end 338.357718 -272.314924)
		(width 0.088646)
		(layer "In6.Cu")
		(net "M_C_CPU0_SA_DQ<8>")
	)
	(segment
		(start 280.73477 -307.81244)
		(end 280.606246 -307.940964)
		(width 0.20066)
		(layer "F.Cu")
		(net "M_C_CPU0_SA_DQ<7>")
	)
	(segment
		(start 281.99588 -307.816758)
		(end 281.788362 -308.024276)
		(width 0.20066)
		(layer "F.Cu")
		(net "M_C_CPU0_SA_DQ<7>")
	)
	(segment
		(start 277.091394 -307.942742)
		(end 276.96541 -307.816758)
		(width 0.20066)
		(layer "F.Cu")
		(net "M_C_CPU0_SA_DQ<7>")
	)
	(segment
		(start 281.129994 -307.81244)
		(end 280.73477 -307.81244)
		(width 0.20066)
		(layer "F.Cu")
		(net "M_C_CPU0_SA_DQ<7>")
	)
	(segment
		(start 280.606246 -308.092602)
		(end 280.457148 -308.2417)
		(width 0.20066)
		(layer "F.Cu")
		(net "M_C_CPU0_SA_DQ<7>")
	)
	(segment
		(start 279.912826 -308.2417)
		(end 277.839932 -308.2417)
		(width 0.1016)
		(layer "F.Cu")
		(net "M_C_CPU0_SA_DQ<7>")
	)
	(segment
		(start 283.916882 -307.816758)
		(end 282.811982 -307.816758)
		(width 0.20066)
		(layer "F.Cu")
		(net "M_C_CPU0_SA_DQ<7>")
	)
	(segment
		(start 277.58771 -308.255924)
		(end 277.233888 -308.255924)
		(width 0.20066)
		(layer "F.Cu")
		(net "M_C_CPU0_SA_DQ<7>")
	)
	(segment
		(start 281.34183 -308.024276)
		(end 281.129994 -307.81244)
		(width 0.20066)
		(layer "F.Cu")
		(net "M_C_CPU0_SA_DQ<7>")
	)
	(segment
		(start 280.606246 -307.940964)
		(end 280.606246 -308.092602)
		(width 0.20066)
		(layer "F.Cu")
		(net "M_C_CPU0_SA_DQ<7>")
	)
	(segment
		(start 281.788362 -308.024276)
		(end 281.34183 -308.024276)
		(width 0.20066)
		(layer "F.Cu")
		(net "M_C_CPU0_SA_DQ<7>")
	)
	(segment
		(start 277.091394 -308.11343)
		(end 277.091394 -307.942742)
		(width 0.20066)
		(layer "F.Cu")
		(net "M_C_CPU0_SA_DQ<7>")
	)
	(segment
		(start 280.457148 -308.2417)
		(end 279.912826 -308.2417)
		(width 0.20066)
		(layer "F.Cu")
		(net "M_C_CPU0_SA_DQ<7>")
	)
	(segment
		(start 277.233888 -308.255924)
		(end 277.091394 -308.11343)
		(width 0.20066)
		(layer "F.Cu")
		(net "M_C_CPU0_SA_DQ<7>")
	)
	(segment
		(start 282.811982 -307.816758)
		(end 281.99588 -307.816758)
		(width 0.20066)
		(layer "F.Cu")
		(net "M_C_CPU0_SA_DQ<7>")
	)
	(segment
		(start 277.601934 -308.2417)
		(end 277.58771 -308.255924)
		(width 0.101854)
		(layer "F.Cu")
		(net "M_C_CPU0_SA_DQ<7>")
	)
	(segment
		(start 276.96541 -307.816758)
		(end 275.268182 -307.816758)
		(width 0.20066)
		(layer "F.Cu")
		(net "M_C_CPU0_SA_DQ<7>")
	)
	(segment
		(start 277.839932 -308.2417)
		(end 277.601934 -308.2417)
		(width 0.101854)
		(layer "F.Cu")
		(net "M_C_CPU0_SA_DQ<7>")
	)
	(arc
		(start 341.364316 -275.35886)
		(mid 341.364252 -275.62683)
		(end 341.364062 -275.8948)
		(width 0.20066)
		(layer "F.Cu")
		(net "M_C_CPU0_SA_DQ<7>")
	)
	(segment
		(start 289.96767 -306.05222)
		(end 289.96767 -307.363876)
		(width 0.18288)
		(layer "In4.Cu")
		(net "M_C_CPU0_SA_DQ<7>")
	)
	(segment
		(start 284.849824 -306.883816)
		(end 283.916882 -307.816758)
		(width 0.18288)
		(layer "In4.Cu")
		(net "M_C_CPU0_SA_DQ<7>")
	)
	(segment
		(start 289.96767 -307.363876)
		(end 289.77209 -307.559456)
		(width 0.18288)
		(layer "In4.Cu")
		(net "M_C_CPU0_SA_DQ<7>")
	)
	(segment
		(start 287.613344 -307.121052)
		(end 287.435544 -307.298852)
		(width 0.18288)
		(layer "In4.Cu")
		(net "M_C_CPU0_SA_DQ<7>")
	)
	(segment
		(start 294.026082 -308.931564)
		(end 294.026082 -308.417976)
		(width 0.18288)
		(layer "In4.Cu")
		(net "M_C_CPU0_SA_DQ<7>")
	)
	(segment
		(start 293.335202 -308.931564)
		(end 293.175182 -309.091584)
		(width 0.18288)
		(layer "In4.Cu")
		(net "M_C_CPU0_SA_DQ<7>")
	)
	(segment
		(start 298.826936 -308.2417)
		(end 297.977052 -309.091584)
		(width 0.18288)
		(layer "In4.Cu")
		(net "M_C_CPU0_SA_DQ<7>")
	)
	(segment
		(start 336.86115 -276.214078)
		(end 336.85226 -276.219158)
		(width 0.088646)
		(layer "In4.Cu")
		(net "M_C_CPU0_SA_DQ<7>")
	)
	(segment
		(start 286.231584 -307.147214)
		(end 286.071564 -307.307234)
		(width 0.18288)
		(layer "In4.Cu")
		(net "M_C_CPU0_SA_DQ<7>")
	)
	(segment
		(start 288.684208 -307.559456)
		(end 288.304224 -307.179472)
		(width 0.18288)
		(layer "In4.Cu")
		(net "M_C_CPU0_SA_DQ<7>")
	)
	(segment
		(start 293.843202 -308.235096)
		(end 293.495222 -308.235096)
		(width 0.18288)
		(layer "In4.Cu")
		(net "M_C_CPU0_SA_DQ<7>")
	)
	(segment
		(start 285.375604 -306.571142)
		(end 285.032704 -306.571142)
		(width 0.18288)
		(layer "In4.Cu")
		(net "M_C_CPU0_SA_DQ<7>")
	)
	(segment
		(start 333.915766 -281.192224)
		(end 333.899256 -281.208734)
		(width 0.088646)
		(layer "In4.Cu")
		(net "M_C_CPU0_SA_DQ<7>")
	)
	(segment
		(start 293.335202 -308.395116)
		(end 293.335202 -308.931564)
		(width 0.18288)
		(layer "In4.Cu")
		(net "M_C_CPU0_SA_DQ<7>")
	)
	(segment
		(start 304.848768 -308.2417)
		(end 298.826936 -308.2417)
		(width 0.18288)
		(layer "In4.Cu")
		(net "M_C_CPU0_SA_DQ<7>")
	)
	(segment
		(start 297.977052 -309.091584)
		(end 294.186102 -309.091584)
		(width 0.18288)
		(layer "In4.Cu")
		(net "M_C_CPU0_SA_DQ<7>")
	)
	(segment
		(start 305.700176 -307.390292)
		(end 304.848768 -308.2417)
		(width 0.18288)
		(layer "In4.Cu")
		(net "M_C_CPU0_SA_DQ<7>")
	)
	(segment
		(start 292.215316 -308.440074)
		(end 292.215316 -307.695092)
		(width 0.18288)
		(layer "In4.Cu")
		(net "M_C_CPU0_SA_DQ<7>")
	)
	(segment
		(start 288.121344 -306.540662)
		(end 287.773364 -306.540662)
		(width 0.18288)
		(layer "In4.Cu")
		(net "M_C_CPU0_SA_DQ<7>")
	)
	(segment
		(start 333.899256 -281.208734)
		(end 333.189326 -281.208734)
		(width 0.088646)
		(layer "In4.Cu")
		(net "M_C_CPU0_SA_DQ<7>")
	)
	(segment
		(start 332.979014 -281.208734)
		(end 327.370186 -286.817562)
		(width 0.18288)
		(layer "In4.Cu")
		(net "M_C_CPU0_SA_DQ<7>")
	)
	(segment
		(start 336.099658 -277.522432)
		(end 336.099658 -277.522686)
		(width 0.088646)
		(layer "In4.Cu")
		(net "M_C_CPU0_SA_DQ<7>")
	)
	(segment
		(start 292.866826 -309.091584)
		(end 292.215316 -308.440074)
		(width 0.18288)
		(layer "In4.Cu")
		(net "M_C_CPU0_SA_DQ<7>")
	)
	(segment
		(start 334.51165 -280.283412)
		(end 334.50276 -280.288492)
		(width 0.088646)
		(layer "In4.Cu")
		(net "M_C_CPU0_SA_DQ<7>")
	)
	(segment
		(start 323.709284 -295.655492)
		(end 316.364112 -303.000664)
		(width 0.18288)
		(layer "In4.Cu")
		(net "M_C_CPU0_SA_DQ<7>")
	)
	(segment
		(start 335.160366 -279.134824)
		(end 335.160366 -279.150318)
		(width 0.088646)
		(layer "In4.Cu")
		(net "M_C_CPU0_SA_DQ<7>")
	)
	(segment
		(start 334.220312 -280.759662)
		(end 334.220312 -280.778204)
		(width 0.088646)
		(layer "In4.Cu")
		(net "M_C_CPU0_SA_DQ<7>")
	)
	(segment
		(start 286.414464 -305.87442)
		(end 286.231584 -306.0573)
		(width 0.18288)
		(layer "In4.Cu")
		(net "M_C_CPU0_SA_DQ<7>")
	)
	(segment
		(start 293.175182 -309.091584)
		(end 292.866826 -309.091584)
		(width 0.18288)
		(layer "In4.Cu")
		(net "M_C_CPU0_SA_DQ<7>")
	)
	(segment
		(start 293.495222 -308.235096)
		(end 293.335202 -308.395116)
		(width 0.18288)
		(layer "In4.Cu")
		(net "M_C_CPU0_SA_DQ<7>")
	)
	(segment
		(start 334.981804 -279.469596)
		(end 334.972914 -279.474676)
		(width 0.088646)
		(layer "In4.Cu")
		(net "M_C_CPU0_SA_DQ<7>")
	)
	(segment
		(start 294.026082 -308.417976)
		(end 293.843202 -308.235096)
		(width 0.18288)
		(layer "In4.Cu")
		(net "M_C_CPU0_SA_DQ<7>")
	)
	(segment
		(start 316.364112 -303.000664)
		(end 316.364112 -303.73193)
		(width 0.18288)
		(layer "In4.Cu")
		(net "M_C_CPU0_SA_DQ<7>")
	)
	(segment
		(start 341.051134 -275.8948)
		(end 340.98611 -275.829776)
		(width 0.088646)
		(layer "In4.Cu")
		(net "M_C_CPU0_SA_DQ<7>")
	)
	(segment
		(start 336.099912 -277.508208)
		(end 336.099658 -277.522432)
		(width 0.088646)
		(layer "In4.Cu")
		(net "M_C_CPU0_SA_DQ<7>")
	)
	(segment
		(start 289.77209 -307.559456)
		(end 288.684208 -307.559456)
		(width 0.18288)
		(layer "In4.Cu")
		(net "M_C_CPU0_SA_DQ<7>")
	)
	(segment
		(start 292.07968 -307.559456)
		(end 290.81857 -307.559456)
		(width 0.18288)
		(layer "In4.Cu")
		(net "M_C_CPU0_SA_DQ<7>")
	)
	(segment
		(start 286.922464 -307.133752)
		(end 286.922464 -306.03444)
		(width 0.18288)
		(layer "In4.Cu")
		(net "M_C_CPU0_SA_DQ<7>")
	)
	(segment
		(start 290.81857 -307.559456)
		(end 290.65855 -307.399436)
		(width 0.18288)
		(layer "In4.Cu")
		(net "M_C_CPU0_SA_DQ<7>")
	)
	(segment
		(start 294.186102 -309.091584)
		(end 294.026082 -308.931564)
		(width 0.18288)
		(layer "In4.Cu")
		(net "M_C_CPU0_SA_DQ<7>")
	)
	(segment
		(start 287.435544 -307.298852)
		(end 287.087564 -307.298852)
		(width 0.18288)
		(layer "In4.Cu")
		(net "M_C_CPU0_SA_DQ<7>")
	)
	(segment
		(start 334.972914 -279.474676)
		(end 334.966818 -279.478232)
		(width 0.088646)
		(layer "In4.Cu")
		(net "M_C_CPU0_SA_DQ<7>")
	)
	(segment
		(start 327.370186 -286.817562)
		(end 323.709284 -295.655492)
		(width 0.18288)
		(layer "In4.Cu")
		(net "M_C_CPU0_SA_DQ<7>")
	)
	(segment
		(start 286.922464 -306.03444)
		(end 286.762444 -305.87442)
		(width 0.18288)
		(layer "In4.Cu")
		(net "M_C_CPU0_SA_DQ<7>")
	)
	(segment
		(start 310.587644 -307.390292)
		(end 305.700176 -307.390292)
		(width 0.18288)
		(layer "In4.Cu")
		(net "M_C_CPU0_SA_DQ<7>")
	)
	(segment
		(start 287.613344 -306.700682)
		(end 287.613344 -307.121052)
		(width 0.18288)
		(layer "In4.Cu")
		(net "M_C_CPU0_SA_DQ<7>")
	)
	(segment
		(start 290.65855 -307.399436)
		(end 290.65855 -306.02936)
		(width 0.18288)
		(layer "In4.Cu")
		(net "M_C_CPU0_SA_DQ<7>")
	)
	(segment
		(start 285.540704 -307.119274)
		(end 285.540704 -306.736242)
		(width 0.18288)
		(layer "In4.Cu")
		(net "M_C_CPU0_SA_DQ<7>")
	)
	(segment
		(start 288.304224 -306.723542)
		(end 288.121344 -306.540662)
		(width 0.18288)
		(layer "In4.Cu")
		(net "M_C_CPU0_SA_DQ<7>")
	)
	(segment
		(start 286.231584 -306.0573)
		(end 286.231584 -307.147214)
		(width 0.18288)
		(layer "In4.Cu")
		(net "M_C_CPU0_SA_DQ<7>")
	)
	(segment
		(start 337.039712 -275.876258)
		(end 337.039712 -275.8948)
		(width 0.088646)
		(layer "In4.Cu")
		(net "M_C_CPU0_SA_DQ<7>")
	)
	(segment
		(start 338.272374 -275.398992)
		(end 338.26196 -275.405088)
		(width 0.088646)
		(layer "In4.Cu")
		(net "M_C_CPU0_SA_DQ<7>")
	)
	(segment
		(start 335.921096 -277.841964)
		(end 335.912206 -277.847044)
		(width 0.088646)
		(layer "In4.Cu")
		(net "M_C_CPU0_SA_DQ<7>")
	)
	(segment
		(start 287.773364 -306.540662)
		(end 287.613344 -306.700682)
		(width 0.18288)
		(layer "In4.Cu")
		(net "M_C_CPU0_SA_DQ<7>")
	)
	(segment
		(start 336.569812 -276.69871)
		(end 336.569812 -276.708616)
		(width 0.088646)
		(layer "In4.Cu")
		(net "M_C_CPU0_SA_DQ<7>")
	)
	(segment
		(start 285.540704 -306.736242)
		(end 285.375604 -306.571142)
		(width 0.18288)
		(layer "In4.Cu")
		(net "M_C_CPU0_SA_DQ<7>")
	)
	(segment
		(start 334.04175 -281.097482)
		(end 334.03286 -281.102562)
		(width 0.088646)
		(layer "In4.Cu")
		(net "M_C_CPU0_SA_DQ<7>")
	)
	(segment
		(start 290.15055 -305.86934)
		(end 289.96767 -306.05222)
		(width 0.18288)
		(layer "In4.Cu")
		(net "M_C_CPU0_SA_DQ<7>")
	)
	(segment
		(start 333.189326 -281.208734)
		(end 332.979014 -281.208734)
		(width 0.18288)
		(layer "In4.Cu")
		(net "M_C_CPU0_SA_DQ<7>")
	)
	(segment
		(start 335.45145 -278.65578)
		(end 335.44256 -278.66086)
		(width 0.088646)
		(layer "In4.Cu")
		(net "M_C_CPU0_SA_DQ<7>")
	)
	(segment
		(start 290.65855 -306.02936)
		(end 290.49853 -305.86934)
		(width 0.18288)
		(layer "In4.Cu")
		(net "M_C_CPU0_SA_DQ<7>")
	)
	(segment
		(start 316.364112 -303.73193)
		(end 314.404502 -305.69154)
		(width 0.18288)
		(layer "In4.Cu")
		(net "M_C_CPU0_SA_DQ<7>")
	)
	(segment
		(start 290.49853 -305.86934)
		(end 290.15055 -305.86934)
		(width 0.18288)
		(layer "In4.Cu")
		(net "M_C_CPU0_SA_DQ<7>")
	)
	(segment
		(start 314.404502 -305.69154)
		(end 312.286396 -305.69154)
		(width 0.18288)
		(layer "In4.Cu")
		(net "M_C_CPU0_SA_DQ<7>")
	)
	(segment
		(start 284.849824 -306.754022)
		(end 284.849824 -306.883816)
		(width 0.18288)
		(layer "In4.Cu")
		(net "M_C_CPU0_SA_DQ<7>")
	)
	(segment
		(start 312.286396 -305.69154)
		(end 310.587644 -307.390292)
		(width 0.18288)
		(layer "In4.Cu")
		(net "M_C_CPU0_SA_DQ<7>")
	)
	(segment
		(start 341.364062 -275.8948)
		(end 341.051134 -275.8948)
		(width 0.088646)
		(layer "In4.Cu")
		(net "M_C_CPU0_SA_DQ<7>")
	)
	(segment
		(start 285.032704 -306.571142)
		(end 284.849824 -306.754022)
		(width 0.18288)
		(layer "In4.Cu")
		(net "M_C_CPU0_SA_DQ<7>")
	)
	(segment
		(start 286.071564 -307.307234)
		(end 285.728664 -307.307234)
		(width 0.18288)
		(layer "In4.Cu")
		(net "M_C_CPU0_SA_DQ<7>")
	)
	(segment
		(start 285.728664 -307.307234)
		(end 285.540704 -307.119274)
		(width 0.18288)
		(layer "In4.Cu")
		(net "M_C_CPU0_SA_DQ<7>")
	)
	(segment
		(start 292.215316 -307.695092)
		(end 292.07968 -307.559456)
		(width 0.18288)
		(layer "In4.Cu")
		(net "M_C_CPU0_SA_DQ<7>")
	)
	(segment
		(start 287.087564 -307.298852)
		(end 286.922464 -307.133752)
		(width 0.18288)
		(layer "In4.Cu")
		(net "M_C_CPU0_SA_DQ<7>")
	)
	(segment
		(start 286.762444 -305.87442)
		(end 286.414464 -305.87442)
		(width 0.18288)
		(layer "In4.Cu")
		(net "M_C_CPU0_SA_DQ<7>")
	)
	(segment
		(start 336.39125 -277.027894)
		(end 336.38236 -277.032974)
		(width 0.088646)
		(layer "In4.Cu")
		(net "M_C_CPU0_SA_DQ<7>")
	)
	(segment
		(start 288.304224 -307.179472)
		(end 288.304224 -306.723542)
		(width 0.18288)
		(layer "In4.Cu")
		(net "M_C_CPU0_SA_DQ<7>")
	)
	(segment
		(start 339.212428 -275.398992)
		(end 339.202014 -275.405088)
		(width 0.088646)
		(layer "In4.Cu")
		(net "M_C_CPU0_SA_DQ<7>")
	)
	(segment
		(start 340.151974 -275.398992)
		(end 340.14156 -275.405088)
		(width 0.088646)
		(layer "In4.Cu")
		(net "M_C_CPU0_SA_DQ<7>")
	)
	(segment
		(start 335.630012 -278.321008)
		(end 335.630012 -278.336502)
		(width 0.088646)
		(layer "In4.Cu")
		(net "M_C_CPU0_SA_DQ<7>")
	)
	(arc
		(start 340.14156 -275.405088)
		(mid 339.954362 -275.455231)
		(end 339.767164 -275.405088)
		(width 0.088646)
		(layer "In4.Cu")
		(net "M_C_CPU0_SA_DQ<7>")
	)
	(arc
		(start 340.98611 -275.829776)
		(mid 340.897041 -275.584347)
		(end 340.707218 -275.405088)
		(width 0.088646)
		(layer "In4.Cu")
		(net "M_C_CPU0_SA_DQ<7>")
	)
	(arc
		(start 334.220312 -280.778204)
		(mid 334.172633 -280.961104)
		(end 334.04175 -281.097482)
		(width 0.088646)
		(layer "In4.Cu")
		(net "M_C_CPU0_SA_DQ<7>")
	)
	(arc
		(start 334.966818 -279.478232)
		(mid 334.764231 -279.684583)
		(end 334.690212 -279.964134)
		(width 0.088646)
		(layer "In4.Cu")
		(net "M_C_CPU0_SA_DQ<7>")
	)
	(arc
		(start 334.690212 -279.964134)
		(mid 334.642533 -280.147034)
		(end 334.51165 -280.283412)
		(width 0.088646)
		(layer "In4.Cu")
		(net "M_C_CPU0_SA_DQ<7>")
	)
	(arc
		(start 337.039712 -275.8948)
		(mid 336.992033 -276.0777)
		(end 336.86115 -276.214078)
		(width 0.088646)
		(layer "In4.Cu")
		(net "M_C_CPU0_SA_DQ<7>")
	)
	(arc
		(start 338.827618 -275.405088)
		(mid 338.550805 -275.329252)
		(end 338.272374 -275.398992)
		(width 0.088646)
		(layer "In4.Cu")
		(net "M_C_CPU0_SA_DQ<7>")
	)
	(arc
		(start 336.099658 -277.522686)
		(mid 336.051979 -277.705586)
		(end 335.921096 -277.841964)
		(width 0.088646)
		(layer "In4.Cu")
		(net "M_C_CPU0_SA_DQ<7>")
	)
	(arc
		(start 338.26196 -275.405088)
		(mid 338.074762 -275.455231)
		(end 337.887564 -275.405088)
		(width 0.088646)
		(layer "In4.Cu")
		(net "M_C_CPU0_SA_DQ<7>")
	)
	(arc
		(start 335.912206 -277.847044)
		(mid 335.709383 -278.047275)
		(end 335.630012 -278.321008)
		(width 0.088646)
		(layer "In4.Cu")
		(net "M_C_CPU0_SA_DQ<7>")
	)
	(arc
		(start 335.44256 -278.66086)
		(mid 335.239737 -278.861091)
		(end 335.160366 -279.134824)
		(width 0.088646)
		(layer "In4.Cu")
		(net "M_C_CPU0_SA_DQ<7>")
	)
	(arc
		(start 334.50276 -280.288492)
		(mid 334.300474 -280.487473)
		(end 334.220312 -280.759662)
		(width 0.088646)
		(layer "In4.Cu")
		(net "M_C_CPU0_SA_DQ<7>")
	)
	(arc
		(start 337.32216 -275.405088)
		(mid 337.119874 -275.604069)
		(end 337.039712 -275.876258)
		(width 0.088646)
		(layer "In4.Cu")
		(net "M_C_CPU0_SA_DQ<7>")
	)
	(arc
		(start 340.707218 -275.405088)
		(mid 340.430405 -275.329252)
		(end 340.151974 -275.398992)
		(width 0.088646)
		(layer "In4.Cu")
		(net "M_C_CPU0_SA_DQ<7>")
	)
	(arc
		(start 336.85226 -276.219158)
		(mid 336.647925 -276.421763)
		(end 336.569812 -276.69871)
		(width 0.088646)
		(layer "In4.Cu")
		(net "M_C_CPU0_SA_DQ<7>")
	)
	(arc
		(start 335.630012 -278.336502)
		(mid 335.582333 -278.519402)
		(end 335.45145 -278.65578)
		(width 0.088646)
		(layer "In4.Cu")
		(net "M_C_CPU0_SA_DQ<7>")
	)
	(arc
		(start 339.767164 -275.405088)
		(mid 339.490605 -275.329379)
		(end 339.212428 -275.398992)
		(width 0.088646)
		(layer "In4.Cu")
		(net "M_C_CPU0_SA_DQ<7>")
	)
	(arc
		(start 334.03286 -281.102562)
		(mid 333.986883 -281.132038)
		(end 333.94396 -281.165808)
		(width 0.088646)
		(layer "In4.Cu")
		(net "M_C_CPU0_SA_DQ<7>")
	)
	(arc
		(start 336.38236 -277.032974)
		(mid 336.179124 -277.233721)
		(end 336.099912 -277.508208)
		(width 0.088646)
		(layer "In4.Cu")
		(net "M_C_CPU0_SA_DQ<7>")
	)
	(arc
		(start 339.202014 -275.405088)
		(mid 339.014816 -275.455231)
		(end 338.827618 -275.405088)
		(width 0.088646)
		(layer "In4.Cu")
		(net "M_C_CPU0_SA_DQ<7>")
	)
	(arc
		(start 336.569812 -276.708616)
		(mid 336.522133 -276.891516)
		(end 336.39125 -277.027894)
		(width 0.088646)
		(layer "In4.Cu")
		(net "M_C_CPU0_SA_DQ<7>")
	)
	(arc
		(start 337.887564 -275.405088)
		(mid 337.604862 -275.329346)
		(end 337.32216 -275.405088)
		(width 0.088646)
		(layer "In4.Cu")
		(net "M_C_CPU0_SA_DQ<7>")
	)
	(arc
		(start 335.160366 -279.150318)
		(mid 335.112687 -279.333218)
		(end 334.981804 -279.469596)
		(width 0.088646)
		(layer "In4.Cu")
		(net "M_C_CPU0_SA_DQ<7>")
	)
	(arc
		(start 333.94396 -281.165808)
		(mid 333.929641 -281.178779)
		(end 333.915766 -281.192224)
		(width 0.088646)
		(layer "In4.Cu")
		(net "M_C_CPU0_SA_DQ<7>")
	)
	(segment
		(start 280.689558 -309.235602)
		(end 280.545794 -309.091838)
		(width 0.20066)
		(layer "F.Cu")
		(net "M_C_CPU0_SA_DQ<6>")
	)
	(segment
		(start 281.497278 -309.51678)
		(end 281.285442 -309.728616)
		(width 0.20066)
		(layer "F.Cu")
		(net "M_C_CPU0_SA_DQ<6>")
	)
	(segment
		(start 276.850348 -309.081678)
		(end 276.415246 -309.51678)
		(width 0.20066)
		(layer "F.Cu")
		(net "M_C_CPU0_SA_DQ<6>")
	)
	(segment
		(start 280.689558 -309.56123)
		(end 280.689558 -309.235602)
		(width 0.20066)
		(layer "F.Cu")
		(net "M_C_CPU0_SA_DQ<6>")
	)
	(segment
		(start 277.852886 -309.091838)
		(end 277.59787 -309.091838)
		(width 0.101854)
		(layer "F.Cu")
		(net "M_C_CPU0_SA_DQ<6>")
	)
	(segment
		(start 280.545794 -309.091838)
		(end 279.912826 -309.091838)
		(width 0.20066)
		(layer "F.Cu")
		(net "M_C_CPU0_SA_DQ<6>")
	)
	(segment
		(start 341.833962 -276.708362)
		(end 341.834216 -276.708616)
		(width 0.20066)
		(layer "F.Cu")
		(net "M_C_CPU0_SA_DQ<6>")
	)
	(segment
		(start 277.58771 -309.081678)
		(end 276.850348 -309.081678)
		(width 0.20066)
		(layer "F.Cu")
		(net "M_C_CPU0_SA_DQ<6>")
	)
	(segment
		(start 282.811982 -309.51678)
		(end 281.497278 -309.51678)
		(width 0.20066)
		(layer "F.Cu")
		(net "M_C_CPU0_SA_DQ<6>")
	)
	(segment
		(start 279.912826 -309.091838)
		(end 277.852886 -309.091838)
		(width 0.1016)
		(layer "F.Cu")
		(net "M_C_CPU0_SA_DQ<6>")
	)
	(segment
		(start 280.856944 -309.728616)
		(end 280.689558 -309.56123)
		(width 0.20066)
		(layer "F.Cu")
		(net "M_C_CPU0_SA_DQ<6>")
	)
	(segment
		(start 283.916882 -309.51678)
		(end 282.811982 -309.51678)
		(width 0.20066)
		(layer "F.Cu")
		(net "M_C_CPU0_SA_DQ<6>")
	)
	(segment
		(start 281.285442 -309.728616)
		(end 280.856944 -309.728616)
		(width 0.20066)
		(layer "F.Cu")
		(net "M_C_CPU0_SA_DQ<6>")
	)
	(segment
		(start 341.833962 -276.172676)
		(end 341.833962 -276.708362)
		(width 0.20066)
		(layer "F.Cu")
		(net "M_C_CPU0_SA_DQ<6>")
	)
	(segment
		(start 276.415246 -309.51678)
		(end 275.268182 -309.51678)
		(width 0.20066)
		(layer "F.Cu")
		(net "M_C_CPU0_SA_DQ<6>")
	)
	(segment
		(start 277.59787 -309.091838)
		(end 277.58771 -309.081678)
		(width 0.101854)
		(layer "F.Cu")
		(net "M_C_CPU0_SA_DQ<6>")
	)
	(segment
		(start 317.359792 -303.413414)
		(end 317.359792 -304.327814)
		(width 0.18288)
		(layer "In4.Cu")
		(net "M_C_CPU0_SA_DQ<6>")
	)
	(segment
		(start 337.039712 -277.512526)
		(end 337.039712 -277.531068)
		(width 0.088646)
		(layer "In4.Cu")
		(net "M_C_CPU0_SA_DQ<6>")
	)
	(segment
		(start 332.305152 -283.355034)
		(end 328.271886 -287.3883)
		(width 0.18288)
		(layer "In4.Cu")
		(net "M_C_CPU0_SA_DQ<6>")
	)
	(segment
		(start 309.178706 -309.021734)
		(end 309.178706 -309.286656)
		(width 0.18288)
		(layer "In4.Cu")
		(net "M_C_CPU0_SA_DQ<6>")
	)
	(segment
		(start 286.366712 -308.91607)
		(end 286.018732 -308.91607)
		(width 0.18288)
		(layer "In4.Cu")
		(net "M_C_CPU0_SA_DQ<6>")
	)
	(segment
		(start 284.401768 -310.001666)
		(end 283.916882 -309.51678)
		(width 0.18288)
		(layer "In4.Cu")
		(net "M_C_CPU0_SA_DQ<6>")
	)
	(segment
		(start 305.086004 -309.941468)
		(end 304.33264 -309.941468)
		(width 0.18288)
		(layer "In4.Cu")
		(net "M_C_CPU0_SA_DQ<6>")
	)
	(segment
		(start 309.178706 -309.286656)
		(end 308.995572 -309.46979)
		(width 0.18288)
		(layer "In4.Cu")
		(net "M_C_CPU0_SA_DQ<6>")
	)
	(segment
		(start 292.449504 -310.591708)
		(end 292.191186 -310.850026)
		(width 0.18288)
		(layer "In4.Cu")
		(net "M_C_CPU0_SA_DQ<6>")
	)
	(segment
		(start 298.61891 -309.941468)
		(end 297.438826 -311.121552)
		(width 0.18288)
		(layer "In4.Cu")
		(net "M_C_CPU0_SA_DQ<6>")
	)
	(segment
		(start 333.574898 -281.840686)
		(end 332.6384 -282.777184)
		(width 0.088646)
		(layer "In4.Cu")
		(net "M_C_CPU0_SA_DQ<6>")
	)
	(segment
		(start 287.830006 -310.001666)
		(end 286.709612 -310.001666)
		(width 0.18288)
		(layer "In4.Cu")
		(net "M_C_CPU0_SA_DQ<6>")
	)
	(segment
		(start 304.33264 -309.941468)
		(end 304.022252 -309.63108)
		(width 0.18288)
		(layer "In4.Cu")
		(net "M_C_CPU0_SA_DQ<6>")
	)
	(segment
		(start 328.271886 -287.3883)
		(end 324.65645 -296.116756)
		(width 0.18288)
		(layer "In4.Cu")
		(net "M_C_CPU0_SA_DQ<6>")
	)
	(segment
		(start 307.20157 -309.178198)
		(end 305.849274 -309.178198)
		(width 0.18288)
		(layer "In4.Cu")
		(net "M_C_CPU0_SA_DQ<6>")
	)
	(segment
		(start 288.195766 -308.767988)
		(end 288.012886 -308.950868)
		(width 0.18288)
		(layer "In4.Cu")
		(net "M_C_CPU0_SA_DQ<6>")
	)
	(segment
		(start 337.33105 -277.027894)
		(end 337.32216 -277.032974)
		(width 0.088646)
		(layer "In4.Cu")
		(net "M_C_CPU0_SA_DQ<6>")
	)
	(segment
		(start 337.509612 -276.69871)
		(end 337.509612 -276.708616)
		(width 0.088646)
		(layer "In4.Cu")
		(net "M_C_CPU0_SA_DQ<6>")
	)
	(segment
		(start 301.565056 -309.697628)
		(end 301.138336 -309.697628)
		(width 0.18288)
		(layer "In4.Cu")
		(net "M_C_CPU0_SA_DQ<6>")
	)
	(segment
		(start 290.195508 -309.748174)
		(end 290.195508 -309.10276)
		(width 0.18288)
		(layer "In4.Cu")
		(net "M_C_CPU0_SA_DQ<6>")
	)
	(segment
		(start 304.022252 -309.63108)
		(end 303.66462 -309.63108)
		(width 0.18288)
		(layer "In4.Cu")
		(net "M_C_CPU0_SA_DQ<6>")
	)
	(segment
		(start 295.34358 -310.791606)
		(end 293.229792 -310.791606)
		(width 0.18288)
		(layer "In4.Cu")
		(net "M_C_CPU0_SA_DQ<6>")
	)
	(segment
		(start 289.504628 -309.725314)
		(end 289.344608 -309.885334)
		(width 0.18288)
		(layer "In4.Cu")
		(net "M_C_CPU0_SA_DQ<6>")
	)
	(segment
		(start 288.703766 -308.928008)
		(end 288.543746 -308.767988)
		(width 0.18288)
		(layer "In4.Cu")
		(net "M_C_CPU0_SA_DQ<6>")
	)
	(segment
		(start 292.191186 -310.850026)
		(end 290.934394 -310.850026)
		(width 0.18288)
		(layer "In4.Cu")
		(net "M_C_CPU0_SA_DQ<6>")
	)
	(segment
		(start 308.47284 -309.021734)
		(end 308.31282 -308.861714)
		(width 0.18288)
		(layer "In4.Cu")
		(net "M_C_CPU0_SA_DQ<6>")
	)
	(segment
		(start 334.97266 -281.102562)
		(end 334.966564 -281.106118)
		(width 0.088646)
		(layer "In4.Cu")
		(net "M_C_CPU0_SA_DQ<6>")
	)
	(segment
		(start 308.31282 -308.861714)
		(end 307.518054 -308.861714)
		(width 0.18288)
		(layer "In4.Cu")
		(net "M_C_CPU0_SA_DQ<6>")
	)
	(segment
		(start 303.354232 -309.941468)
		(end 301.808896 -309.941468)
		(width 0.18288)
		(layer "In4.Cu")
		(net "M_C_CPU0_SA_DQ<6>")
	)
	(segment
		(start 285.698692 -310.001666)
		(end 284.401768 -310.001666)
		(width 0.18288)
		(layer "In4.Cu")
		(net "M_C_CPU0_SA_DQ<6>")
	)
	(segment
		(start 297.438826 -311.121552)
		(end 295.673526 -311.121552)
		(width 0.18288)
		(layer "In4.Cu")
		(net "M_C_CPU0_SA_DQ<6>")
	)
	(segment
		(start 293.229792 -310.791606)
		(end 293.029894 -310.591708)
		(width 0.18288)
		(layer "In4.Cu")
		(net "M_C_CPU0_SA_DQ<6>")
	)
	(segment
		(start 286.549592 -309.841646)
		(end 286.549592 -309.09895)
		(width 0.18288)
		(layer "In4.Cu")
		(net "M_C_CPU0_SA_DQ<6>")
	)
	(segment
		(start 301.808896 -309.941468)
		(end 301.565056 -309.697628)
		(width 0.18288)
		(layer "In4.Cu")
		(net "M_C_CPU0_SA_DQ<6>")
	)
	(segment
		(start 289.344608 -309.885334)
		(end 288.8869 -309.885334)
		(width 0.18288)
		(layer "In4.Cu")
		(net "M_C_CPU0_SA_DQ<6>")
	)
	(segment
		(start 309.338726 -308.861714)
		(end 309.178706 -309.021734)
		(width 0.18288)
		(layer "In4.Cu")
		(net "M_C_CPU0_SA_DQ<6>")
	)
	(segment
		(start 290.195508 -309.10276)
		(end 290.012628 -308.91988)
		(width 0.18288)
		(layer "In4.Cu")
		(net "M_C_CPU0_SA_DQ<6>")
	)
	(segment
		(start 301.138336 -309.697628)
		(end 300.894496 -309.941468)
		(width 0.18288)
		(layer "In4.Cu")
		(net "M_C_CPU0_SA_DQ<6>")
	)
	(segment
		(start 335.538064 -281.102562)
		(end 335.523332 -281.093926)
		(width 0.088646)
		(layer "In4.Cu")
		(net "M_C_CPU0_SA_DQ<6>")
	)
	(segment
		(start 333.845662 -281.840686)
		(end 333.574898 -281.840686)
		(width 0.088646)
		(layer "In4.Cu")
		(net "M_C_CPU0_SA_DQ<6>")
	)
	(segment
		(start 336.099912 -279.140412)
		(end 336.099912 -279.150318)
		(width 0.088646)
		(layer "In4.Cu")
		(net "M_C_CPU0_SA_DQ<6>")
	)
	(segment
		(start 334.51165 -281.911298)
		(end 334.50276 -281.916378)
		(width 0.088646)
		(layer "In4.Cu")
		(net "M_C_CPU0_SA_DQ<6>")
	)
	(segment
		(start 286.018732 -308.91607)
		(end 285.858712 -309.07609)
		(width 0.18288)
		(layer "In4.Cu")
		(net "M_C_CPU0_SA_DQ<6>")
	)
	(segment
		(start 314.264294 -307.423312)
		(end 313.026044 -307.423312)
		(width 0.18288)
		(layer "In4.Cu")
		(net "M_C_CPU0_SA_DQ<6>")
	)
	(segment
		(start 305.849274 -309.178198)
		(end 305.086004 -309.941468)
		(width 0.18288)
		(layer "In4.Cu")
		(net "M_C_CPU0_SA_DQ<6>")
	)
	(segment
		(start 288.012886 -309.818786)
		(end 287.830006 -310.001666)
		(width 0.18288)
		(layer "In4.Cu")
		(net "M_C_CPU0_SA_DQ<6>")
	)
	(segment
		(start 288.012886 -308.950868)
		(end 288.012886 -309.818786)
		(width 0.18288)
		(layer "In4.Cu")
		(net "M_C_CPU0_SA_DQ<6>")
	)
	(segment
		(start 341.264494 -276.509226)
		(end 341.029544 -276.274276)
		(width 0.088646)
		(layer "In4.Cu")
		(net "M_C_CPU0_SA_DQ<6>")
	)
	(segment
		(start 332.6384 -282.777184)
		(end 332.6384 -283.021786)
		(width 0.088646)
		(layer "In4.Cu")
		(net "M_C_CPU0_SA_DQ<6>")
	)
	(segment
		(start 313.026044 -307.423312)
		(end 312.278014 -308.171342)
		(width 0.18288)
		(layer "In4.Cu")
		(net "M_C_CPU0_SA_DQ<6>")
	)
	(segment
		(start 286.549592 -309.09895)
		(end 286.366712 -308.91607)
		(width 0.18288)
		(layer "In4.Cu")
		(net "M_C_CPU0_SA_DQ<6>")
	)
	(segment
		(start 310.876442 -308.861714)
		(end 309.338726 -308.861714)
		(width 0.18288)
		(layer "In4.Cu")
		(net "M_C_CPU0_SA_DQ<6>")
	)
	(segment
		(start 308.47284 -309.30977)
		(end 308.47284 -309.021734)
		(width 0.18288)
		(layer "In4.Cu")
		(net "M_C_CPU0_SA_DQ<6>")
	)
	(segment
		(start 288.543746 -308.767988)
		(end 288.195766 -308.767988)
		(width 0.18288)
		(layer "In4.Cu")
		(net "M_C_CPU0_SA_DQ<6>")
	)
	(segment
		(start 311.566814 -308.171342)
		(end 310.876442 -308.861714)
		(width 0.18288)
		(layer "In4.Cu")
		(net "M_C_CPU0_SA_DQ<6>")
	)
	(segment
		(start 295.673526 -311.121552)
		(end 295.34358 -310.791606)
		(width 0.18288)
		(layer "In4.Cu")
		(net "M_C_CPU0_SA_DQ<6>")
	)
	(segment
		(start 289.504628 -309.0799)
		(end 289.504628 -309.725314)
		(width 0.18288)
		(layer "In4.Cu")
		(net "M_C_CPU0_SA_DQ<6>")
	)
	(segment
		(start 300.894496 -309.941468)
		(end 298.61891 -309.941468)
		(width 0.18288)
		(layer "In4.Cu")
		(net "M_C_CPU0_SA_DQ<6>")
	)
	(segment
		(start 335.91246 -280.453846)
		(end 335.92135 -280.458926)
		(width 0.088646)
		(layer "In4.Cu")
		(net "M_C_CPU0_SA_DQ<6>")
	)
	(segment
		(start 336.569812 -278.322278)
		(end 336.569812 -278.336502)
		(width 0.088646)
		(layer "In4.Cu")
		(net "M_C_CPU0_SA_DQ<6>")
	)
	(segment
		(start 307.518054 -308.861714)
		(end 307.20157 -309.178198)
		(width 0.18288)
		(layer "In4.Cu")
		(net "M_C_CPU0_SA_DQ<6>")
	)
	(segment
		(start 308.995572 -309.46979)
		(end 308.63286 -309.46979)
		(width 0.18288)
		(layer "In4.Cu")
		(net "M_C_CPU0_SA_DQ<6>")
	)
	(segment
		(start 288.703766 -309.7022)
		(end 288.703766 -308.928008)
		(width 0.18288)
		(layer "In4.Cu")
		(net "M_C_CPU0_SA_DQ<6>")
	)
	(segment
		(start 335.92135 -279.469596)
		(end 335.91246 -279.474676)
		(width 0.088646)
		(layer "In4.Cu")
		(net "M_C_CPU0_SA_DQ<6>")
	)
	(segment
		(start 308.63286 -309.46979)
		(end 308.47284 -309.30977)
		(width 0.18288)
		(layer "In4.Cu")
		(net "M_C_CPU0_SA_DQ<6>")
	)
	(segment
		(start 293.029894 -310.591708)
		(end 292.449504 -310.591708)
		(width 0.18288)
		(layer "In4.Cu")
		(net "M_C_CPU0_SA_DQ<6>")
	)
	(segment
		(start 285.858712 -309.841646)
		(end 285.698692 -310.001666)
		(width 0.18288)
		(layer "In4.Cu")
		(net "M_C_CPU0_SA_DQ<6>")
	)
	(segment
		(start 341.834216 -276.708616)
		(end 341.745824 -276.708616)
		(width 0.088646)
		(layer "In4.Cu")
		(net "M_C_CPU0_SA_DQ<6>")
	)
	(segment
		(start 290.934394 -310.850026)
		(end 290.724844 -310.640476)
		(width 0.18288)
		(layer "In4.Cu")
		(net "M_C_CPU0_SA_DQ<6>")
	)
	(segment
		(start 335.630012 -279.954228)
		(end 335.630012 -279.982676)
		(width 0.088646)
		(layer "In4.Cu")
		(net "M_C_CPU0_SA_DQ<6>")
	)
	(segment
		(start 290.724844 -310.27751)
		(end 290.195508 -309.748174)
		(width 0.18288)
		(layer "In4.Cu")
		(net "M_C_CPU0_SA_DQ<6>")
	)
	(segment
		(start 303.66462 -309.63108)
		(end 303.354232 -309.941468)
		(width 0.18288)
		(layer "In4.Cu")
		(net "M_C_CPU0_SA_DQ<6>")
	)
	(segment
		(start 290.724844 -310.640476)
		(end 290.724844 -310.27751)
		(width 0.18288)
		(layer "In4.Cu")
		(net "M_C_CPU0_SA_DQ<6>")
	)
	(segment
		(start 340.237064 -276.219158)
		(end 340.222332 -276.210522)
		(width 0.088646)
		(layer "In4.Cu")
		(net "M_C_CPU0_SA_DQ<6>")
	)
	(segment
		(start 290.012628 -308.91988)
		(end 289.664648 -308.91988)
		(width 0.18288)
		(layer "In4.Cu")
		(net "M_C_CPU0_SA_DQ<6>")
	)
	(segment
		(start 285.858712 -309.07609)
		(end 285.858712 -309.841646)
		(width 0.18288)
		(layer "In4.Cu")
		(net "M_C_CPU0_SA_DQ<6>")
	)
	(segment
		(start 324.65645 -296.116756)
		(end 317.359792 -303.413414)
		(width 0.18288)
		(layer "In4.Cu")
		(net "M_C_CPU0_SA_DQ<6>")
	)
	(segment
		(start 335.92135 -281.097482)
		(end 335.91246 -281.102562)
		(width 0.088646)
		(layer "In4.Cu")
		(net "M_C_CPU0_SA_DQ<6>")
	)
	(segment
		(start 289.664648 -308.91988)
		(end 289.504628 -309.0799)
		(width 0.18288)
		(layer "In4.Cu")
		(net "M_C_CPU0_SA_DQ<6>")
	)
	(segment
		(start 336.39125 -278.65578)
		(end 336.38236 -278.66086)
		(width 0.088646)
		(layer "In4.Cu")
		(net "M_C_CPU0_SA_DQ<6>")
	)
	(segment
		(start 286.709612 -310.001666)
		(end 286.549592 -309.841646)
		(width 0.18288)
		(layer "In4.Cu")
		(net "M_C_CPU0_SA_DQ<6>")
	)
	(segment
		(start 332.6384 -283.021786)
		(end 332.305152 -283.355034)
		(width 0.088646)
		(layer "In4.Cu")
		(net "M_C_CPU0_SA_DQ<6>")
	)
	(segment
		(start 317.359792 -304.327814)
		(end 314.264294 -307.423312)
		(width 0.18288)
		(layer "In4.Cu")
		(net "M_C_CPU0_SA_DQ<6>")
	)
	(segment
		(start 312.278014 -308.171342)
		(end 311.566814 -308.171342)
		(width 0.18288)
		(layer "In4.Cu")
		(net "M_C_CPU0_SA_DQ<6>")
	)
	(segment
		(start 288.8869 -309.885334)
		(end 288.703766 -309.7022)
		(width 0.18288)
		(layer "In4.Cu")
		(net "M_C_CPU0_SA_DQ<6>")
	)
	(arc
		(start 335.630012 -279.982676)
		(mid 335.710174 -280.254865)
		(end 335.91246 -280.453846)
		(width 0.088646)
		(layer "In4.Cu")
		(net "M_C_CPU0_SA_DQ<6>")
	)
	(arc
		(start 334.50276 -281.916378)
		(mid 334.315562 -281.966521)
		(end 334.128364 -281.916378)
		(width 0.088646)
		(layer "In4.Cu")
		(net "M_C_CPU0_SA_DQ<6>")
	)
	(arc
		(start 341.029544 -276.274276)
		(mid 340.82987 -276.175814)
		(end 340.61146 -276.219158)
		(width 0.088646)
		(layer "In4.Cu")
		(net "M_C_CPU0_SA_DQ<6>")
	)
	(arc
		(start 334.128364 -281.916378)
		(mid 333.991995 -281.859936)
		(end 333.845662 -281.840686)
		(width 0.088646)
		(layer "In4.Cu")
		(net "M_C_CPU0_SA_DQ<6>")
	)
	(arc
		(start 339.67166 -276.219158)
		(mid 339.484462 -276.269301)
		(end 339.297264 -276.219158)
		(width 0.088646)
		(layer "In4.Cu")
		(net "M_C_CPU0_SA_DQ<6>")
	)
	(arc
		(start 335.91246 -281.102562)
		(mid 335.725262 -281.152705)
		(end 335.538064 -281.102562)
		(width 0.088646)
		(layer "In4.Cu")
		(net "M_C_CPU0_SA_DQ<6>")
	)
	(arc
		(start 336.099912 -279.150318)
		(mid 336.052233 -279.333218)
		(end 335.92135 -279.469596)
		(width 0.088646)
		(layer "In4.Cu")
		(net "M_C_CPU0_SA_DQ<6>")
	)
	(arc
		(start 335.91246 -279.474676)
		(mid 335.708125 -279.677281)
		(end 335.630012 -279.954228)
		(width 0.088646)
		(layer "In4.Cu")
		(net "M_C_CPU0_SA_DQ<6>")
	)
	(arc
		(start 336.38236 -278.66086)
		(mid 336.178025 -278.863465)
		(end 336.099912 -279.140412)
		(width 0.088646)
		(layer "In4.Cu")
		(net "M_C_CPU0_SA_DQ<6>")
	)
	(arc
		(start 338.73186 -276.219158)
		(mid 338.544662 -276.269301)
		(end 338.357464 -276.219158)
		(width 0.088646)
		(layer "In4.Cu")
		(net "M_C_CPU0_SA_DQ<6>")
	)
	(arc
		(start 335.92135 -280.458926)
		(mid 336.099947 -280.778204)
		(end 335.92135 -281.097482)
		(width 0.088646)
		(layer "In4.Cu")
		(net "M_C_CPU0_SA_DQ<6>")
	)
	(arc
		(start 336.569812 -278.336502)
		(mid 336.522133 -278.519402)
		(end 336.39125 -278.65578)
		(width 0.088646)
		(layer "In4.Cu")
		(net "M_C_CPU0_SA_DQ<6>")
	)
	(arc
		(start 334.690212 -281.59202)
		(mid 334.642533 -281.77492)
		(end 334.51165 -281.911298)
		(width 0.088646)
		(layer "In4.Cu")
		(net "M_C_CPU0_SA_DQ<6>")
	)
	(arc
		(start 338.357464 -276.219158)
		(mid 338.074762 -276.143382)
		(end 337.79206 -276.219158)
		(width 0.088646)
		(layer "In4.Cu")
		(net "M_C_CPU0_SA_DQ<6>")
	)
	(arc
		(start 337.039712 -277.531068)
		(mid 336.987442 -277.713433)
		(end 336.852514 -277.84679)
		(width 0.088646)
		(layer "In4.Cu")
		(net "M_C_CPU0_SA_DQ<6>")
	)
	(arc
		(start 334.966564 -281.106118)
		(mid 334.764151 -281.312531)
		(end 334.690212 -281.59202)
		(width 0.088646)
		(layer "In4.Cu")
		(net "M_C_CPU0_SA_DQ<6>")
	)
	(arc
		(start 337.32216 -277.032974)
		(mid 337.117825 -277.235579)
		(end 337.039712 -277.512526)
		(width 0.088646)
		(layer "In4.Cu")
		(net "M_C_CPU0_SA_DQ<6>")
	)
	(arc
		(start 335.523332 -281.093926)
		(mid 335.246857 -281.026606)
		(end 334.97266 -281.102562)
		(width 0.088646)
		(layer "In4.Cu")
		(net "M_C_CPU0_SA_DQ<6>")
	)
	(arc
		(start 341.745824 -276.708616)
		(mid 341.485324 -276.656799)
		(end 341.264494 -276.509226)
		(width 0.088646)
		(layer "In4.Cu")
		(net "M_C_CPU0_SA_DQ<6>")
	)
	(arc
		(start 340.61146 -276.219158)
		(mid 340.424262 -276.269301)
		(end 340.237064 -276.219158)
		(width 0.088646)
		(layer "In4.Cu")
		(net "M_C_CPU0_SA_DQ<6>")
	)
	(arc
		(start 336.852514 -277.84679)
		(mid 336.649033 -278.047594)
		(end 336.569812 -278.322278)
		(width 0.088646)
		(layer "In4.Cu")
		(net "M_C_CPU0_SA_DQ<6>")
	)
	(arc
		(start 337.79206 -276.219158)
		(mid 337.587725 -276.421763)
		(end 337.509612 -276.69871)
		(width 0.088646)
		(layer "In4.Cu")
		(net "M_C_CPU0_SA_DQ<6>")
	)
	(arc
		(start 337.509612 -276.708616)
		(mid 337.461933 -276.891516)
		(end 337.33105 -277.027894)
		(width 0.088646)
		(layer "In4.Cu")
		(net "M_C_CPU0_SA_DQ<6>")
	)
	(arc
		(start 339.297264 -276.219158)
		(mid 339.014562 -276.143382)
		(end 338.73186 -276.219158)
		(width 0.088646)
		(layer "In4.Cu")
		(net "M_C_CPU0_SA_DQ<6>")
	)
	(arc
		(start 340.222332 -276.210522)
		(mid 339.945857 -276.143202)
		(end 339.67166 -276.219158)
		(width 0.088646)
		(layer "In4.Cu")
		(net "M_C_CPU0_SA_DQ<6>")
	)
	(segment
		(start 274.152868 -308.2417)
		(end 274.143978 -308.23281)
		(width 0.1016)
		(layer "F.Cu")
		(net "M_C_CPU0_SA_DQ<5>")
	)
	(segment
		(start 273.37258 -308.39537)
		(end 273.37258 -308.723538)
		(width 0.20066)
		(layer "F.Cu")
		(net "M_C_CPU0_SA_DQ<5>")
	)
	(segment
		(start 273.37258 -308.723538)
		(end 273.218148 -308.87797)
		(width 0.20066)
		(layer "F.Cu")
		(net "M_C_CPU0_SA_DQ<5>")
	)
	(segment
		(start 272.502376 -308.666642)
		(end 271.168114 -308.666642)
		(width 0.20066)
		(layer "F.Cu")
		(net "M_C_CPU0_SA_DQ<5>")
	)
	(segment
		(start 277.072598 -308.666642)
		(end 276.647656 -308.2417)
		(width 0.20066)
		(layer "F.Cu")
		(net "M_C_CPU0_SA_DQ<5>")
	)
	(segment
		(start 274.143978 -308.23281)
		(end 273.53514 -308.23281)
		(width 0.20066)
		(layer "F.Cu")
		(net "M_C_CPU0_SA_DQ<5>")
	)
	(segment
		(start 273.218148 -308.87797)
		(end 272.713704 -308.87797)
		(width 0.20066)
		(layer "F.Cu")
		(net "M_C_CPU0_SA_DQ<5>")
	)
	(segment
		(start 273.53514 -308.23281)
		(end 273.37258 -308.39537)
		(width 0.20066)
		(layer "F.Cu")
		(net "M_C_CPU0_SA_DQ<5>")
	)
	(segment
		(start 279.816814 -308.666642)
		(end 278.711914 -308.666642)
		(width 0.20066)
		(layer "F.Cu")
		(net "M_C_CPU0_SA_DQ<5>")
	)
	(segment
		(start 276.138386 -308.2417)
		(end 274.152868 -308.2417)
		(width 0.1016)
		(layer "F.Cu")
		(net "M_C_CPU0_SA_DQ<5>")
	)
	(segment
		(start 276.647656 -308.2417)
		(end 276.469094 -308.2417)
		(width 0.20066)
		(layer "F.Cu")
		(net "M_C_CPU0_SA_DQ<5>")
	)
	(segment
		(start 276.469094 -308.2417)
		(end 276.138386 -308.2417)
		(width 0.101854)
		(layer "F.Cu")
		(net "M_C_CPU0_SA_DQ<5>")
	)
	(segment
		(start 272.713704 -308.87797)
		(end 272.502376 -308.666642)
		(width 0.20066)
		(layer "F.Cu")
		(net "M_C_CPU0_SA_DQ<5>")
	)
	(segment
		(start 278.711914 -308.666642)
		(end 277.072598 -308.666642)
		(width 0.20066)
		(layer "F.Cu")
		(net "M_C_CPU0_SA_DQ<5>")
	)
	(arc
		(start 340.424516 -275.35886)
		(mid 340.424452 -275.62683)
		(end 340.424262 -275.8948)
		(width 0.20066)
		(layer "F.Cu")
		(net "M_C_CPU0_SA_DQ<5>")
	)
	(segment
		(start 283.160216 -308.273958)
		(end 282.922472 -308.036214)
		(width 0.18288)
		(layer "In4.Cu")
		(net "M_C_CPU0_SA_DQ<5>")
	)
	(segment
		(start 333.38389 -281.535632)
		(end 332.26502 -282.654502)
		(width 0.088646)
		(layer "In4.Cu")
		(net "M_C_CPU0_SA_DQ<5>")
	)
	(segment
		(start 314.30976 -306.544472)
		(end 313.15533 -306.544472)
		(width 0.18288)
		(layer "In4.Cu")
		(net "M_C_CPU0_SA_DQ<5>")
	)
	(segment
		(start 281.611832 -308.146704)
		(end 281.451812 -307.986684)
		(width 0.18288)
		(layer "In4.Cu")
		(net "M_C_CPU0_SA_DQ<5>")
	)
	(segment
		(start 286.561784 -307.9877)
		(end 286.401764 -307.82768)
		(width 0.18288)
		(layer "In4.Cu")
		(net "M_C_CPU0_SA_DQ<5>")
	)
	(segment
		(start 280.760932 -307.655468)
		(end 280.760932 -307.986684)
		(width 0.18288)
		(layer "In4.Cu")
		(net "M_C_CPU0_SA_DQ<5>")
	)
	(segment
		(start 290.928044 -308.273958)
		(end 290.80079 -308.146704)
		(width 0.18288)
		(layer "In4.Cu")
		(net "M_C_CPU0_SA_DQ<5>")
	)
	(segment
		(start 316.861952 -303.207166)
		(end 316.861952 -303.99228)
		(width 0.18288)
		(layer "In4.Cu")
		(net "M_C_CPU0_SA_DQ<5>")
	)
	(segment
		(start 334.598264 -280.453846)
		(end 334.589374 -280.458926)
		(width 0.088646)
		(layer "In4.Cu")
		(net "M_C_CPU0_SA_DQ<5>")
	)
	(segment
		(start 282.739592 -307.345588)
		(end 282.391612 -307.345588)
		(width 0.18288)
		(layer "In4.Cu")
		(net "M_C_CPU0_SA_DQ<5>")
	)
	(segment
		(start 296.895012 -309.678324)
		(end 296.270426 -309.678324)
		(width 0.18288)
		(layer "In4.Cu")
		(net "M_C_CPU0_SA_DQ<5>")
	)
	(segment
		(start 337.230212 -275.8948)
		(end 337.230212 -275.904706)
		(width 0.088646)
		(layer "In4.Cu")
		(net "M_C_CPU0_SA_DQ<5>")
	)
	(segment
		(start 298.755054 -309.091584)
		(end 297.904916 -309.941722)
		(width 0.18288)
		(layer "In4.Cu")
		(net "M_C_CPU0_SA_DQ<5>")
	)
	(segment
		(start 340.73719 -275.8948)
		(end 340.79434 -275.83765)
		(width 0.088646)
		(layer "In4.Cu")
		(net "M_C_CPU0_SA_DQ<5>")
	)
	(segment
		(start 280.336752 -308.146704)
		(end 279.816814 -308.666642)
		(width 0.18288)
		(layer "In4.Cu")
		(net "M_C_CPU0_SA_DQ<5>")
	)
	(segment
		(start 301.721266 -309.091584)
		(end 301.425102 -308.79542)
		(width 0.18288)
		(layer "In4.Cu")
		(net "M_C_CPU0_SA_DQ<5>")
	)
	(segment
		(start 297.904916 -309.941722)
		(end 297.15841 -309.941722)
		(width 0.18288)
		(layer "In4.Cu")
		(net "M_C_CPU0_SA_DQ<5>")
	)
	(segment
		(start 339.297264 -275.570442)
		(end 339.282532 -275.579078)
		(width 0.088646)
		(layer "In4.Cu")
		(net "M_C_CPU0_SA_DQ<5>")
	)
	(segment
		(start 282.231592 -307.986684)
		(end 282.071572 -308.146704)
		(width 0.18288)
		(layer "In4.Cu")
		(net "M_C_CPU0_SA_DQ<5>")
	)
	(segment
		(start 286.05353 -307.82768)
		(end 285.361888 -308.519322)
		(width 0.18288)
		(layer "In4.Cu")
		(net "M_C_CPU0_SA_DQ<5>")
	)
	(segment
		(start 305.071018 -309.091584)
		(end 301.721266 -309.091584)
		(width 0.18288)
		(layer "In4.Cu")
		(net "M_C_CPU0_SA_DQ<5>")
	)
	(segment
		(start 282.071572 -308.146704)
		(end 281.611832 -308.146704)
		(width 0.18288)
		(layer "In4.Cu")
		(net "M_C_CPU0_SA_DQ<5>")
	)
	(segment
		(start 334.134206 -281.264106)
		(end 334.12811 -281.267662)
		(width 0.088646)
		(layer "In4.Cu")
		(net "M_C_CPU0_SA_DQ<5>")
	)
	(segment
		(start 282.391612 -307.345588)
		(end 282.231592 -307.505608)
		(width 0.18288)
		(layer "In4.Cu")
		(net "M_C_CPU0_SA_DQ<5>")
	)
	(segment
		(start 296.007028 -309.941722)
		(end 291.899086 -309.941722)
		(width 0.18288)
		(layer "In4.Cu")
		(net "M_C_CPU0_SA_DQ<5>")
	)
	(segment
		(start 335.068164 -279.639776)
		(end 335.059274 -279.644856)
		(width 0.088646)
		(layer "In4.Cu")
		(net "M_C_CPU0_SA_DQ<5>")
	)
	(segment
		(start 336.760312 -276.708616)
		(end 336.760312 -276.72284)
		(width 0.088646)
		(layer "In4.Cu")
		(net "M_C_CPU0_SA_DQ<5>")
	)
	(segment
		(start 281.268932 -307.495448)
		(end 280.920952 -307.495448)
		(width 0.18288)
		(layer "In4.Cu")
		(net "M_C_CPU0_SA_DQ<5>")
	)
	(segment
		(start 336.290412 -277.529036)
		(end 336.290158 -277.53818)
		(width 0.088646)
		(layer "In4.Cu")
		(net "M_C_CPU0_SA_DQ<5>")
	)
	(segment
		(start 334.880712 -279.964134)
		(end 334.880712 -279.982676)
		(width 0.088646)
		(layer "In4.Cu")
		(net "M_C_CPU0_SA_DQ<5>")
	)
	(segment
		(start 280.920952 -307.495448)
		(end 280.760932 -307.655468)
		(width 0.18288)
		(layer "In4.Cu")
		(net "M_C_CPU0_SA_DQ<5>")
	)
	(segment
		(start 297.15841 -309.941722)
		(end 296.895012 -309.678324)
		(width 0.18288)
		(layer "In4.Cu")
		(net "M_C_CPU0_SA_DQ<5>")
	)
	(segment
		(start 311.432702 -307.587142)
		(end 310.671718 -308.348126)
		(width 0.18288)
		(layer "In4.Cu")
		(net "M_C_CPU0_SA_DQ<5>")
	)
	(segment
		(start 324.141846 -295.927272)
		(end 316.861952 -303.207166)
		(width 0.18288)
		(layer "In4.Cu")
		(net "M_C_CPU0_SA_DQ<5>")
	)
	(segment
		(start 313.15533 -306.544472)
		(end 312.11266 -307.587142)
		(width 0.18288)
		(layer "In4.Cu")
		(net "M_C_CPU0_SA_DQ<5>")
	)
	(segment
		(start 282.922472 -307.528468)
		(end 282.739592 -307.345588)
		(width 0.18288)
		(layer "In4.Cu")
		(net "M_C_CPU0_SA_DQ<5>")
	)
	(segment
		(start 306.019708 -308.142894)
		(end 305.071018 -309.091584)
		(width 0.18288)
		(layer "In4.Cu")
		(net "M_C_CPU0_SA_DQ<5>")
	)
	(segment
		(start 316.861952 -303.99228)
		(end 314.30976 -306.544472)
		(width 0.18288)
		(layer "In4.Cu")
		(net "M_C_CPU0_SA_DQ<5>")
	)
	(segment
		(start 287.859216 -308.146704)
		(end 287.486598 -308.519322)
		(width 0.18288)
		(layer "In4.Cu")
		(net "M_C_CPU0_SA_DQ<5>")
	)
	(segment
		(start 327.783698 -287.135824)
		(end 324.141846 -295.927272)
		(width 0.18288)
		(layer "In4.Cu")
		(net "M_C_CPU0_SA_DQ<5>")
	)
	(segment
		(start 281.451812 -307.986684)
		(end 281.451812 -307.678328)
		(width 0.18288)
		(layer "In4.Cu")
		(net "M_C_CPU0_SA_DQ<5>")
	)
	(segment
		(start 286.721804 -308.519322)
		(end 286.561784 -308.359302)
		(width 0.18288)
		(layer "In4.Cu")
		(net "M_C_CPU0_SA_DQ<5>")
	)
	(segment
		(start 283.57449 -309.091584)
		(end 283.160216 -308.67731)
		(width 0.18288)
		(layer "In4.Cu")
		(net "M_C_CPU0_SA_DQ<5>")
	)
	(segment
		(start 337.417664 -275.570442)
		(end 337.408774 -275.575522)
		(width 0.088646)
		(layer "In4.Cu")
		(net "M_C_CPU0_SA_DQ<5>")
	)
	(segment
		(start 282.922472 -308.036214)
		(end 282.922472 -307.528468)
		(width 0.18288)
		(layer "In4.Cu")
		(net "M_C_CPU0_SA_DQ<5>")
	)
	(segment
		(start 307.140356 -308.142894)
		(end 306.019708 -308.142894)
		(width 0.18288)
		(layer "In4.Cu")
		(net "M_C_CPU0_SA_DQ<5>")
	)
	(segment
		(start 336.290412 -277.51405)
		(end 336.290412 -277.529036)
		(width 0.088646)
		(layer "In4.Cu")
		(net "M_C_CPU0_SA_DQ<5>")
	)
	(segment
		(start 307.345588 -308.348126)
		(end 307.140356 -308.142894)
		(width 0.18288)
		(layer "In4.Cu")
		(net "M_C_CPU0_SA_DQ<5>")
	)
	(segment
		(start 286.561784 -308.359302)
		(end 286.561784 -307.9877)
		(width 0.18288)
		(layer "In4.Cu")
		(net "M_C_CPU0_SA_DQ<5>")
	)
	(segment
		(start 284.220666 -309.091584)
		(end 283.57449 -309.091584)
		(width 0.18288)
		(layer "In4.Cu")
		(net "M_C_CPU0_SA_DQ<5>")
	)
	(segment
		(start 333.841852 -281.535632)
		(end 333.38389 -281.535632)
		(width 0.088646)
		(layer "In4.Cu")
		(net "M_C_CPU0_SA_DQ<5>")
	)
	(segment
		(start 312.11266 -307.587142)
		(end 311.432702 -307.587142)
		(width 0.18288)
		(layer "In4.Cu")
		(net "M_C_CPU0_SA_DQ<5>")
	)
	(segment
		(start 335.538318 -278.82596)
		(end 335.529428 -278.83104)
		(width 0.088646)
		(layer "In4.Cu")
		(net "M_C_CPU0_SA_DQ<5>")
	)
	(segment
		(start 283.160216 -308.67731)
		(end 283.160216 -308.273958)
		(width 0.18288)
		(layer "In4.Cu")
		(net "M_C_CPU0_SA_DQ<5>")
	)
	(segment
		(start 296.270426 -309.678324)
		(end 296.007028 -309.941722)
		(width 0.18288)
		(layer "In4.Cu")
		(net "M_C_CPU0_SA_DQ<5>")
	)
	(segment
		(start 332.26502 -282.654502)
		(end 327.783698 -287.135824)
		(width 0.18288)
		(layer "In4.Cu")
		(net "M_C_CPU0_SA_DQ<5>")
	)
	(segment
		(start 290.928044 -308.97068)
		(end 290.928044 -308.273958)
		(width 0.18288)
		(layer "In4.Cu")
		(net "M_C_CPU0_SA_DQ<5>")
	)
	(segment
		(start 280.600912 -308.146704)
		(end 280.336752 -308.146704)
		(width 0.18288)
		(layer "In4.Cu")
		(net "M_C_CPU0_SA_DQ<5>")
	)
	(segment
		(start 301.425102 -308.79542)
		(end 301.00397 -308.79542)
		(width 0.18288)
		(layer "In4.Cu")
		(net "M_C_CPU0_SA_DQ<5>")
	)
	(segment
		(start 286.401764 -307.82768)
		(end 286.05353 -307.82768)
		(width 0.18288)
		(layer "In4.Cu")
		(net "M_C_CPU0_SA_DQ<5>")
	)
	(segment
		(start 336.007964 -278.012144)
		(end 335.999074 -278.017224)
		(width 0.088646)
		(layer "In4.Cu")
		(net "M_C_CPU0_SA_DQ<5>")
	)
	(segment
		(start 336.947764 -276.384258)
		(end 336.938874 -276.389338)
		(width 0.088646)
		(layer "In4.Cu")
		(net "M_C_CPU0_SA_DQ<5>")
	)
	(segment
		(start 300.707806 -309.091584)
		(end 298.755054 -309.091584)
		(width 0.18288)
		(layer "In4.Cu")
		(net "M_C_CPU0_SA_DQ<5>")
	)
	(segment
		(start 282.231592 -307.505608)
		(end 282.231592 -307.986684)
		(width 0.18288)
		(layer "In4.Cu")
		(net "M_C_CPU0_SA_DQ<5>")
	)
	(segment
		(start 284.792928 -308.519322)
		(end 284.220666 -309.091584)
		(width 0.18288)
		(layer "In4.Cu")
		(net "M_C_CPU0_SA_DQ<5>")
	)
	(segment
		(start 291.899086 -309.941722)
		(end 290.928044 -308.97068)
		(width 0.18288)
		(layer "In4.Cu")
		(net "M_C_CPU0_SA_DQ<5>")
	)
	(segment
		(start 340.62035 -275.575522)
		(end 340.61146 -275.570442)
		(width 0.088646)
		(layer "In4.Cu")
		(net "M_C_CPU0_SA_DQ<5>")
	)
	(segment
		(start 310.671718 -308.348126)
		(end 307.345588 -308.348126)
		(width 0.18288)
		(layer "In4.Cu")
		(net "M_C_CPU0_SA_DQ<5>")
	)
	(segment
		(start 334.050386 -281.327098)
		(end 333.841852 -281.535632)
		(width 0.088646)
		(layer "In4.Cu")
		(net "M_C_CPU0_SA_DQ<5>")
	)
	(segment
		(start 280.760932 -307.986684)
		(end 280.600912 -308.146704)
		(width 0.18288)
		(layer "In4.Cu")
		(net "M_C_CPU0_SA_DQ<5>")
	)
	(segment
		(start 340.424262 -275.8948)
		(end 340.73719 -275.8948)
		(width 0.088646)
		(layer "In4.Cu")
		(net "M_C_CPU0_SA_DQ<5>")
	)
	(segment
		(start 290.80079 -308.146704)
		(end 287.859216 -308.146704)
		(width 0.18288)
		(layer "In4.Cu")
		(net "M_C_CPU0_SA_DQ<5>")
	)
	(segment
		(start 301.00397 -308.79542)
		(end 300.707806 -309.091584)
		(width 0.18288)
		(layer "In4.Cu")
		(net "M_C_CPU0_SA_DQ<5>")
	)
	(segment
		(start 335.820512 -278.336502)
		(end 335.820512 -278.351996)
		(width 0.088646)
		(layer "In4.Cu")
		(net "M_C_CPU0_SA_DQ<5>")
	)
	(segment
		(start 287.486598 -308.519322)
		(end 286.721804 -308.519322)
		(width 0.18288)
		(layer "In4.Cu")
		(net "M_C_CPU0_SA_DQ<5>")
	)
	(segment
		(start 335.07426 -279.63622)
		(end 335.068164 -279.639776)
		(width 0.088646)
		(layer "In4.Cu")
		(net "M_C_CPU0_SA_DQ<5>")
	)
	(segment
		(start 281.451812 -307.678328)
		(end 281.268932 -307.495448)
		(width 0.18288)
		(layer "In4.Cu")
		(net "M_C_CPU0_SA_DQ<5>")
	)
	(segment
		(start 285.361888 -308.519322)
		(end 284.792928 -308.519322)
		(width 0.18288)
		(layer "In4.Cu")
		(net "M_C_CPU0_SA_DQ<5>")
	)
	(arc
		(start 339.282532 -275.579078)
		(mid 339.006091 -275.646244)
		(end 338.73186 -275.570442)
		(width 0.088646)
		(layer "In4.Cu")
		(net "M_C_CPU0_SA_DQ<5>")
	)
	(arc
		(start 339.67166 -275.570442)
		(mid 339.484462 -275.520299)
		(end 339.297264 -275.570442)
		(width 0.088646)
		(layer "In4.Cu")
		(net "M_C_CPU0_SA_DQ<5>")
	)
	(arc
		(start 335.059274 -279.644856)
		(mid 334.92836 -279.781216)
		(end 334.880712 -279.964134)
		(width 0.088646)
		(layer "In4.Cu")
		(net "M_C_CPU0_SA_DQ<5>")
	)
	(arc
		(start 337.408774 -275.575522)
		(mid 337.27786 -275.711882)
		(end 337.230212 -275.8948)
		(width 0.088646)
		(layer "In4.Cu")
		(net "M_C_CPU0_SA_DQ<5>")
	)
	(arc
		(start 334.880712 -279.982676)
		(mid 334.80055 -280.254865)
		(end 334.598264 -280.453846)
		(width 0.088646)
		(layer "In4.Cu")
		(net "M_C_CPU0_SA_DQ<5>")
	)
	(arc
		(start 335.820512 -278.351996)
		(mid 335.741142 -278.62573)
		(end 335.538318 -278.82596)
		(width 0.088646)
		(layer "In4.Cu")
		(net "M_C_CPU0_SA_DQ<5>")
	)
	(arc
		(start 334.410812 -280.778204)
		(mid 334.336821 -281.05777)
		(end 334.134206 -281.264106)
		(width 0.088646)
		(layer "In4.Cu")
		(net "M_C_CPU0_SA_DQ<5>")
	)
	(arc
		(start 340.61146 -275.570442)
		(mid 340.424262 -275.520299)
		(end 340.237064 -275.570442)
		(width 0.088646)
		(layer "In4.Cu")
		(net "M_C_CPU0_SA_DQ<5>")
	)
	(arc
		(start 336.47761 -277.198328)
		(mid 336.342677 -277.331682)
		(end 336.290412 -277.51405)
		(width 0.088646)
		(layer "In4.Cu")
		(net "M_C_CPU0_SA_DQ<5>")
	)
	(arc
		(start 335.999074 -278.017224)
		(mid 335.86816 -278.153584)
		(end 335.820512 -278.336502)
		(width 0.088646)
		(layer "In4.Cu")
		(net "M_C_CPU0_SA_DQ<5>")
	)
	(arc
		(start 340.237064 -275.570442)
		(mid 339.954362 -275.646184)
		(end 339.67166 -275.570442)
		(width 0.088646)
		(layer "In4.Cu")
		(net "M_C_CPU0_SA_DQ<5>")
	)
	(arc
		(start 337.230212 -275.904706)
		(mid 337.152101 -276.181655)
		(end 336.947764 -276.384258)
		(width 0.088646)
		(layer "In4.Cu")
		(net "M_C_CPU0_SA_DQ<5>")
	)
	(arc
		(start 336.290158 -277.53818)
		(mid 336.210788 -277.811914)
		(end 336.007964 -278.012144)
		(width 0.088646)
		(layer "In4.Cu")
		(net "M_C_CPU0_SA_DQ<5>")
	)
	(arc
		(start 338.357464 -275.570442)
		(mid 338.074762 -275.646184)
		(end 337.79206 -275.570442)
		(width 0.088646)
		(layer "In4.Cu")
		(net "M_C_CPU0_SA_DQ<5>")
	)
	(arc
		(start 337.79206 -275.570442)
		(mid 337.604862 -275.520299)
		(end 337.417664 -275.570442)
		(width 0.088646)
		(layer "In4.Cu")
		(net "M_C_CPU0_SA_DQ<5>")
	)
	(arc
		(start 334.589374 -280.458926)
		(mid 334.45846 -280.595286)
		(end 334.410812 -280.778204)
		(width 0.088646)
		(layer "In4.Cu")
		(net "M_C_CPU0_SA_DQ<5>")
	)
	(arc
		(start 338.73186 -275.570442)
		(mid 338.544662 -275.520299)
		(end 338.357464 -275.570442)
		(width 0.088646)
		(layer "In4.Cu")
		(net "M_C_CPU0_SA_DQ<5>")
	)
	(arc
		(start 336.760312 -276.72284)
		(mid 336.681093 -276.997525)
		(end 336.47761 -277.198328)
		(width 0.088646)
		(layer "In4.Cu")
		(net "M_C_CPU0_SA_DQ<5>")
	)
	(arc
		(start 336.938874 -276.389338)
		(mid 336.80796 -276.525698)
		(end 336.760312 -276.708616)
		(width 0.088646)
		(layer "In4.Cu")
		(net "M_C_CPU0_SA_DQ<5>")
	)
	(arc
		(start 335.529428 -278.83104)
		(mid 335.398514 -278.9674)
		(end 335.350866 -279.150318)
		(width 0.088646)
		(layer "In4.Cu")
		(net "M_C_CPU0_SA_DQ<5>")
	)
	(arc
		(start 335.350866 -279.150318)
		(mid 335.276875 -279.429884)
		(end 335.07426 -279.63622)
		(width 0.088646)
		(layer "In4.Cu")
		(net "M_C_CPU0_SA_DQ<5>")
	)
	(arc
		(start 340.79434 -275.83765)
		(mid 340.736221 -275.687409)
		(end 340.62035 -275.575522)
		(width 0.088646)
		(layer "In4.Cu")
		(net "M_C_CPU0_SA_DQ<5>")
	)
	(arc
		(start 334.12811 -281.267662)
		(mid 334.087301 -281.294834)
		(end 334.050386 -281.327098)
		(width 0.088646)
		(layer "In4.Cu")
		(net "M_C_CPU0_SA_DQ<5>")
	)
	(segment
		(start 277.342854 -310.366664)
		(end 276.917912 -309.941722)
		(width 0.20066)
		(layer "F.Cu")
		(net "M_C_CPU0_SA_DQ<4>")
	)
	(segment
		(start 279.816814 -310.366664)
		(end 278.711914 -310.366664)
		(width 0.20066)
		(layer "F.Cu")
		(net "M_C_CPU0_SA_DQ<4>")
	)
	(segment
		(start 274.152106 -309.941722)
		(end 274.143978 -309.933594)
		(width 0.101854)
		(layer "F.Cu")
		(net "M_C_CPU0_SA_DQ<4>")
	)
	(segment
		(start 274.143978 -309.933594)
		(end 273.58213 -309.933594)
		(width 0.20066)
		(layer "F.Cu")
		(net "M_C_CPU0_SA_DQ<4>")
	)
	(segment
		(start 274.40001 -309.941722)
		(end 274.152106 -309.941722)
		(width 0.101854)
		(layer "F.Cu")
		(net "M_C_CPU0_SA_DQ<4>")
	)
	(segment
		(start 272.741136 -310.605424)
		(end 272.502376 -310.366664)
		(width 0.20066)
		(layer "F.Cu")
		(net "M_C_CPU0_SA_DQ<4>")
	)
	(segment
		(start 276.469094 -309.941722)
		(end 274.40001 -309.941722)
		(width 0.1016)
		(layer "F.Cu")
		(net "M_C_CPU0_SA_DQ<4>")
	)
	(segment
		(start 272.502376 -310.366664)
		(end 271.168114 -310.366664)
		(width 0.20066)
		(layer "F.Cu")
		(net "M_C_CPU0_SA_DQ<4>")
	)
	(segment
		(start 278.711914 -310.366664)
		(end 277.342854 -310.366664)
		(width 0.20066)
		(layer "F.Cu")
		(net "M_C_CPU0_SA_DQ<4>")
	)
	(segment
		(start 276.917912 -309.941722)
		(end 276.469094 -309.941722)
		(width 0.20066)
		(layer "F.Cu")
		(net "M_C_CPU0_SA_DQ<4>")
	)
	(segment
		(start 273.37258 -310.143144)
		(end 273.37258 -310.432704)
		(width 0.20066)
		(layer "F.Cu")
		(net "M_C_CPU0_SA_DQ<4>")
	)
	(segment
		(start 273.37258 -310.432704)
		(end 273.19986 -310.605424)
		(width 0.20066)
		(layer "F.Cu")
		(net "M_C_CPU0_SA_DQ<4>")
	)
	(segment
		(start 273.58213 -309.933594)
		(end 273.37258 -310.143144)
		(width 0.20066)
		(layer "F.Cu")
		(net "M_C_CPU0_SA_DQ<4>")
	)
	(segment
		(start 273.19986 -310.605424)
		(end 272.741136 -310.605424)
		(width 0.20066)
		(layer "F.Cu")
		(net "M_C_CPU0_SA_DQ<4>")
	)
	(segment
		(start 339.954362 -276.172676)
		(end 339.954362 -276.708362)
		(width 0.20066)
		(layer "F.Cu")
		(net "M_C_CPU0_SA_DQ<4>")
	)
	(segment
		(start 339.954362 -276.708362)
		(end 339.954616 -276.708616)
		(width 0.20066)
		(layer "F.Cu")
		(net "M_C_CPU0_SA_DQ<4>")
	)
	(segment
		(start 283.02458 -309.828946)
		(end 282.894278 -309.828946)
		(width 0.18288)
		(layer "In4.Cu")
		(net "M_C_CPU0_SA_DQ<4>")
	)
	(segment
		(start 292.080442 -311.444132)
		(end 290.6649 -311.444132)
		(width 0.18288)
		(layer "In4.Cu")
		(net "M_C_CPU0_SA_DQ<4>")
	)
	(segment
		(start 305.198272 -310.791606)
		(end 301.578518 -310.791606)
		(width 0.18288)
		(layer "In4.Cu")
		(net "M_C_CPU0_SA_DQ<4>")
	)
	(segment
		(start 292.278054 -311.641744)
		(end 292.080442 -311.444132)
		(width 0.18288)
		(layer "In4.Cu")
		(net "M_C_CPU0_SA_DQ<4>")
	)
	(segment
		(start 328.721212 -287.669224)
		(end 325.123556 -296.353992)
		(width 0.18288)
		(layer "In4.Cu")
		(net "M_C_CPU0_SA_DQ<4>")
	)
	(segment
		(start 282.203398 -308.885336)
		(end 282.043378 -309.045356)
		(width 0.18288)
		(layer "In4.Cu")
		(net "M_C_CPU0_SA_DQ<4>")
	)
	(segment
		(start 336.477864 -278.82596)
		(end 336.468974 -278.83104)
		(width 0.088646)
		(layer "In4.Cu")
		(net "M_C_CPU0_SA_DQ<4>")
	)
	(segment
		(start 336.290412 -279.150318)
		(end 336.290412 -279.160224)
		(width 0.088646)
		(layer "In4.Cu")
		(net "M_C_CPU0_SA_DQ<4>")
	)
	(segment
		(start 335.068418 -281.267662)
		(end 335.059528 -281.272742)
		(width 0.088646)
		(layer "In4.Cu")
		(net "M_C_CPU0_SA_DQ<4>")
	)
	(segment
		(start 332.987142 -282.697682)
		(end 332.987142 -283.403294)
		(width 0.088646)
		(layer "In4.Cu")
		(net "M_C_CPU0_SA_DQ<4>")
	)
	(segment
		(start 337.887564 -276.384258)
		(end 337.878674 -276.389338)
		(width 0.088646)
		(layer "In4.Cu")
		(net "M_C_CPU0_SA_DQ<4>")
	)
	(segment
		(start 280.661618 -309.07228)
		(end 280.661618 -309.668926)
		(width 0.18288)
		(layer "In4.Cu")
		(net "M_C_CPU0_SA_DQ<4>")
	)
	(segment
		(start 336.947764 -278.012144)
		(end 336.938874 -278.017224)
		(width 0.088646)
		(layer "In4.Cu")
		(net "M_C_CPU0_SA_DQ<4>")
	)
	(segment
		(start 332.987142 -283.403294)
		(end 332.67015 -283.720286)
		(width 0.088646)
		(layer "In4.Cu")
		(net "M_C_CPU0_SA_DQ<4>")
	)
	(segment
		(start 281.352498 -309.04942)
		(end 281.192478 -308.8894)
		(width 0.18288)
		(layer "In4.Cu")
		(net "M_C_CPU0_SA_DQ<4>")
	)
	(segment
		(start 296.659554 -312.127392)
		(end 296.286174 -312.127392)
		(width 0.18288)
		(layer "In4.Cu")
		(net "M_C_CPU0_SA_DQ<4>")
	)
	(segment
		(start 290.6649 -311.444132)
		(end 290.012374 -310.791606)
		(width 0.18288)
		(layer "In4.Cu")
		(net "M_C_CPU0_SA_DQ<4>")
	)
	(segment
		(start 281.352498 -309.646066)
		(end 281.352498 -309.04942)
		(width 0.18288)
		(layer "In4.Cu")
		(net "M_C_CPU0_SA_DQ<4>")
	)
	(segment
		(start 282.894278 -309.828946)
		(end 282.734258 -309.668926)
		(width 0.18288)
		(layer "In4.Cu")
		(net "M_C_CPU0_SA_DQ<4>")
	)
	(segment
		(start 281.192478 -308.8894)
		(end 280.844498 -308.8894)
		(width 0.18288)
		(layer "In4.Cu")
		(net "M_C_CPU0_SA_DQ<4>")
	)
	(segment
		(start 280.661618 -309.668926)
		(end 280.501598 -309.828946)
		(width 0.18288)
		(layer "In4.Cu")
		(net "M_C_CPU0_SA_DQ<4>")
	)
	(segment
		(start 283.307028 -310.111394)
		(end 283.02458 -309.828946)
		(width 0.18288)
		(layer "In4.Cu")
		(net "M_C_CPU0_SA_DQ<4>")
	)
	(segment
		(start 333.653892 -282.030932)
		(end 332.987142 -282.697682)
		(width 0.088646)
		(layer "In4.Cu")
		(net "M_C_CPU0_SA_DQ<4>")
	)
	(segment
		(start 280.354532 -309.828946)
		(end 279.816814 -310.366664)
		(width 0.18288)
		(layer "In4.Cu")
		(net "M_C_CPU0_SA_DQ<4>")
	)
	(segment
		(start 333.845662 -282.030932)
		(end 333.653892 -282.030932)
		(width 0.088646)
		(layer "In4.Cu")
		(net "M_C_CPU0_SA_DQ<4>")
	)
	(segment
		(start 311.217056 -309.980076)
		(end 307.357526 -309.980076)
		(width 0.18288)
		(layer "In4.Cu")
		(net "M_C_CPU0_SA_DQ<4>")
	)
	(segment
		(start 297.794172 -311.641744)
		(end 296.979594 -311.641744)
		(width 0.18288)
		(layer "In4.Cu")
		(net "M_C_CPU0_SA_DQ<4>")
	)
	(segment
		(start 301.578518 -310.791606)
		(end 301.418498 -310.951626)
		(width 0.18288)
		(layer "In4.Cu")
		(net "M_C_CPU0_SA_DQ<4>")
	)
	(segment
		(start 296.979594 -311.641744)
		(end 296.819574 -311.801764)
		(width 0.18288)
		(layer "In4.Cu")
		(net "M_C_CPU0_SA_DQ<4>")
	)
	(segment
		(start 339.584284 -276.608286)
		(end 339.20176 -276.384258)
		(width 0.088646)
		(layer "In4.Cu")
		(net "M_C_CPU0_SA_DQ<4>")
	)
	(segment
		(start 283.307028 -310.588406)
		(end 283.307028 -310.111394)
		(width 0.18288)
		(layer "In4.Cu")
		(net "M_C_CPU0_SA_DQ<4>")
	)
	(segment
		(start 313.222894 -307.974238)
		(end 311.217056 -309.980076)
		(width 0.18288)
		(layer "In4.Cu")
		(net "M_C_CPU0_SA_DQ<4>")
	)
	(segment
		(start 337.230466 -277.513796)
		(end 337.230466 -277.536656)
		(width 0.088646)
		(layer "In4.Cu")
		(net "M_C_CPU0_SA_DQ<4>")
	)
	(segment
		(start 282.551378 -308.885336)
		(end 282.203398 -308.885336)
		(width 0.18288)
		(layer "In4.Cu")
		(net "M_C_CPU0_SA_DQ<4>")
	)
	(segment
		(start 336.290412 -280.759662)
		(end 336.290412 -280.78811)
		(width 0.088646)
		(layer "In4.Cu")
		(net "M_C_CPU0_SA_DQ<4>")
	)
	(segment
		(start 300.567598 -310.791606)
		(end 298.64431 -310.791606)
		(width 0.18288)
		(layer "In4.Cu")
		(net "M_C_CPU0_SA_DQ<4>")
	)
	(segment
		(start 317.857632 -304.538126)
		(end 314.42152 -307.974238)
		(width 0.18288)
		(layer "In4.Cu")
		(net "M_C_CPU0_SA_DQ<4>")
	)
	(segment
		(start 334.602836 -282.078938)
		(end 334.598518 -282.081478)
		(width 0.088646)
		(layer "In4.Cu")
		(net "M_C_CPU0_SA_DQ<4>")
	)
	(segment
		(start 307.213508 -309.836058)
		(end 306.15382 -309.836058)
		(width 0.18288)
		(layer "In4.Cu")
		(net "M_C_CPU0_SA_DQ<4>")
	)
	(segment
		(start 337.700112 -276.708616)
		(end 337.700112 -276.718522)
		(width 0.088646)
		(layer "In4.Cu")
		(net "M_C_CPU0_SA_DQ<4>")
	)
	(segment
		(start 280.501598 -309.828946)
		(end 280.354532 -309.828946)
		(width 0.18288)
		(layer "In4.Cu")
		(net "M_C_CPU0_SA_DQ<4>")
	)
	(segment
		(start 306.15382 -309.836058)
		(end 305.198272 -310.791606)
		(width 0.18288)
		(layer "In4.Cu")
		(net "M_C_CPU0_SA_DQ<4>")
	)
	(segment
		(start 314.42152 -307.974238)
		(end 313.222894 -307.974238)
		(width 0.18288)
		(layer "In4.Cu")
		(net "M_C_CPU0_SA_DQ<4>")
	)
	(segment
		(start 307.357526 -309.980076)
		(end 307.213508 -309.836058)
		(width 0.18288)
		(layer "In4.Cu")
		(net "M_C_CPU0_SA_DQ<4>")
	)
	(segment
		(start 336.760312 -278.336502)
		(end 336.760312 -278.346408)
		(width 0.088646)
		(layer "In4.Cu")
		(net "M_C_CPU0_SA_DQ<4>")
	)
	(segment
		(start 325.123556 -296.353992)
		(end 317.857632 -303.619916)
		(width 0.18288)
		(layer "In4.Cu")
		(net "M_C_CPU0_SA_DQ<4>")
	)
	(segment
		(start 296.126154 -311.967372)
		(end 296.126154 -311.801764)
		(width 0.18288)
		(layer "In4.Cu")
		(net "M_C_CPU0_SA_DQ<4>")
	)
	(segment
		(start 282.734258 -309.668926)
		(end 282.734258 -309.068216)
		(width 0.18288)
		(layer "In4.Cu")
		(net "M_C_CPU0_SA_DQ<4>")
	)
	(segment
		(start 301.418498 -311.277)
		(end 301.235618 -311.45988)
		(width 0.18288)
		(layer "In4.Cu")
		(net "M_C_CPU0_SA_DQ<4>")
	)
	(segment
		(start 301.418498 -310.951626)
		(end 301.418498 -311.277)
		(width 0.18288)
		(layer "In4.Cu")
		(net "M_C_CPU0_SA_DQ<4>")
	)
	(segment
		(start 334.604614 -282.077922)
		(end 334.602836 -282.078938)
		(width 0.088646)
		(layer "In4.Cu")
		(net "M_C_CPU0_SA_DQ<4>")
	)
	(segment
		(start 317.857632 -303.619916)
		(end 317.857632 -304.538126)
		(width 0.18288)
		(layer "In4.Cu")
		(net "M_C_CPU0_SA_DQ<4>")
	)
	(segment
		(start 300.727618 -310.951626)
		(end 300.567598 -310.791606)
		(width 0.18288)
		(layer "In4.Cu")
		(net "M_C_CPU0_SA_DQ<4>")
	)
	(segment
		(start 296.126154 -311.801764)
		(end 295.966134 -311.641744)
		(width 0.18288)
		(layer "In4.Cu")
		(net "M_C_CPU0_SA_DQ<4>")
	)
	(segment
		(start 336.007964 -279.639776)
		(end 335.999074 -279.644856)
		(width 0.088646)
		(layer "In4.Cu")
		(net "M_C_CPU0_SA_DQ<4>")
	)
	(segment
		(start 300.727618 -311.29986)
		(end 300.727618 -310.951626)
		(width 0.18288)
		(layer "In4.Cu")
		(net "M_C_CPU0_SA_DQ<4>")
	)
	(segment
		(start 335.453228 -281.273758)
		(end 335.442814 -281.267662)
		(width 0.088646)
		(layer "In4.Cu")
		(net "M_C_CPU0_SA_DQ<4>")
	)
	(segment
		(start 295.966134 -311.641744)
		(end 292.278054 -311.641744)
		(width 0.18288)
		(layer "In4.Cu")
		(net "M_C_CPU0_SA_DQ<4>")
	)
	(segment
		(start 301.235618 -311.45988)
		(end 300.887638 -311.45988)
		(width 0.18288)
		(layer "In4.Cu")
		(net "M_C_CPU0_SA_DQ<4>")
	)
	(segment
		(start 296.286174 -312.127392)
		(end 296.126154 -311.967372)
		(width 0.18288)
		(layer "In4.Cu")
		(net "M_C_CPU0_SA_DQ<4>")
	)
	(segment
		(start 296.819574 -311.801764)
		(end 296.819574 -311.967372)
		(width 0.18288)
		(layer "In4.Cu")
		(net "M_C_CPU0_SA_DQ<4>")
	)
	(segment
		(start 282.043378 -309.668926)
		(end 281.883358 -309.828946)
		(width 0.18288)
		(layer "In4.Cu")
		(net "M_C_CPU0_SA_DQ<4>")
	)
	(segment
		(start 283.510228 -310.791606)
		(end 283.307028 -310.588406)
		(width 0.18288)
		(layer "In4.Cu")
		(net "M_C_CPU0_SA_DQ<4>")
	)
	(segment
		(start 298.64431 -310.791606)
		(end 297.794172 -311.641744)
		(width 0.18288)
		(layer "In4.Cu")
		(net "M_C_CPU0_SA_DQ<4>")
	)
	(segment
		(start 335.999074 -280.283412)
		(end 336.007964 -280.288492)
		(width 0.088646)
		(layer "In4.Cu")
		(net "M_C_CPU0_SA_DQ<4>")
	)
	(segment
		(start 282.043378 -309.045356)
		(end 282.043378 -309.668926)
		(width 0.18288)
		(layer "In4.Cu")
		(net "M_C_CPU0_SA_DQ<4>")
	)
	(segment
		(start 282.734258 -309.068216)
		(end 282.551378 -308.885336)
		(width 0.18288)
		(layer "In4.Cu")
		(net "M_C_CPU0_SA_DQ<4>")
	)
	(segment
		(start 300.887638 -311.45988)
		(end 300.727618 -311.29986)
		(width 0.18288)
		(layer "In4.Cu")
		(net "M_C_CPU0_SA_DQ<4>")
	)
	(segment
		(start 296.819574 -311.967372)
		(end 296.659554 -312.127392)
		(width 0.18288)
		(layer "In4.Cu")
		(net "M_C_CPU0_SA_DQ<4>")
	)
	(segment
		(start 332.67015 -283.720286)
		(end 328.721212 -287.669224)
		(width 0.18288)
		(layer "In4.Cu")
		(net "M_C_CPU0_SA_DQ<4>")
	)
	(segment
		(start 281.883358 -309.828946)
		(end 281.535378 -309.828946)
		(width 0.18288)
		(layer "In4.Cu")
		(net "M_C_CPU0_SA_DQ<4>")
	)
	(segment
		(start 281.535378 -309.828946)
		(end 281.352498 -309.646066)
		(width 0.18288)
		(layer "In4.Cu")
		(net "M_C_CPU0_SA_DQ<4>")
	)
	(segment
		(start 290.012374 -310.791606)
		(end 283.510228 -310.791606)
		(width 0.18288)
		(layer "In4.Cu")
		(net "M_C_CPU0_SA_DQ<4>")
	)
	(segment
		(start 280.844498 -308.8894)
		(end 280.661618 -309.07228)
		(width 0.18288)
		(layer "In4.Cu")
		(net "M_C_CPU0_SA_DQ<4>")
	)
	(arc
		(start 337.700112 -276.718522)
		(mid 337.622001 -276.995471)
		(end 337.417664 -277.198074)
		(width 0.088646)
		(layer "In4.Cu")
		(net "M_C_CPU0_SA_DQ<4>")
	)
	(arc
		(start 336.468974 -278.83104)
		(mid 336.33806 -278.9674)
		(end 336.290412 -279.150318)
		(width 0.088646)
		(layer "In4.Cu")
		(net "M_C_CPU0_SA_DQ<4>")
	)
	(arc
		(start 336.007964 -280.288492)
		(mid 336.21025 -280.487473)
		(end 336.290412 -280.759662)
		(width 0.088646)
		(layer "In4.Cu")
		(net "M_C_CPU0_SA_DQ<4>")
	)
	(arc
		(start 337.417664 -277.198074)
		(mid 337.282731 -277.331428)
		(end 337.230466 -277.513796)
		(width 0.088646)
		(layer "In4.Cu")
		(net "M_C_CPU0_SA_DQ<4>")
	)
	(arc
		(start 339.20176 -276.384258)
		(mid 339.014562 -276.334115)
		(end 338.827364 -276.384258)
		(width 0.088646)
		(layer "In4.Cu")
		(net "M_C_CPU0_SA_DQ<4>")
	)
	(arc
		(start 339.954616 -276.708616)
		(mid 339.76276 -276.683133)
		(end 339.584284 -276.608286)
		(width 0.088646)
		(layer "In4.Cu")
		(net "M_C_CPU0_SA_DQ<4>")
	)
	(arc
		(start 336.760312 -278.346408)
		(mid 336.682201 -278.623357)
		(end 336.477864 -278.82596)
		(width 0.088646)
		(layer "In4.Cu")
		(net "M_C_CPU0_SA_DQ<4>")
	)
	(arc
		(start 336.007964 -281.267662)
		(mid 335.731405 -281.343405)
		(end 335.453228 -281.273758)
		(width 0.088646)
		(layer "In4.Cu")
		(net "M_C_CPU0_SA_DQ<4>")
	)
	(arc
		(start 335.059528 -281.272742)
		(mid 334.928614 -281.409102)
		(end 334.880966 -281.59202)
		(width 0.088646)
		(layer "In4.Cu")
		(net "M_C_CPU0_SA_DQ<4>")
	)
	(arc
		(start 334.043274 -282.087574)
		(mid 333.94843 -282.045423)
		(end 333.845662 -282.030932)
		(width 0.088646)
		(layer "In4.Cu")
		(net "M_C_CPU0_SA_DQ<4>")
	)
	(arc
		(start 334.598518 -282.081478)
		(mid 334.321705 -282.157348)
		(end 334.043274 -282.087574)
		(width 0.088646)
		(layer "In4.Cu")
		(net "M_C_CPU0_SA_DQ<4>")
	)
	(arc
		(start 336.290412 -280.78811)
		(mid 336.212301 -281.065059)
		(end 336.007964 -281.267662)
		(width 0.088646)
		(layer "In4.Cu")
		(net "M_C_CPU0_SA_DQ<4>")
	)
	(arc
		(start 338.26196 -276.384258)
		(mid 338.074762 -276.334115)
		(end 337.887564 -276.384258)
		(width 0.088646)
		(layer "In4.Cu")
		(net "M_C_CPU0_SA_DQ<4>")
	)
	(arc
		(start 337.230466 -277.536656)
		(mid 337.151247 -277.811341)
		(end 336.947764 -278.012144)
		(width 0.088646)
		(layer "In4.Cu")
		(net "M_C_CPU0_SA_DQ<4>")
	)
	(arc
		(start 336.290412 -279.160224)
		(mid 336.212301 -279.437173)
		(end 336.007964 -279.639776)
		(width 0.088646)
		(layer "In4.Cu")
		(net "M_C_CPU0_SA_DQ<4>")
	)
	(arc
		(start 335.442814 -281.267662)
		(mid 335.255616 -281.217519)
		(end 335.068418 -281.267662)
		(width 0.088646)
		(layer "In4.Cu")
		(net "M_C_CPU0_SA_DQ<4>")
	)
	(arc
		(start 337.878674 -276.389338)
		(mid 337.74776 -276.525698)
		(end 337.700112 -276.708616)
		(width 0.088646)
		(layer "In4.Cu")
		(net "M_C_CPU0_SA_DQ<4>")
	)
	(arc
		(start 335.999074 -279.644856)
		(mid 335.820477 -279.964134)
		(end 335.999074 -280.283412)
		(width 0.088646)
		(layer "In4.Cu")
		(net "M_C_CPU0_SA_DQ<4>")
	)
	(arc
		(start 338.827364 -276.384258)
		(mid 338.544662 -276.460034)
		(end 338.26196 -276.384258)
		(width 0.088646)
		(layer "In4.Cu")
		(net "M_C_CPU0_SA_DQ<4>")
	)
	(arc
		(start 334.880966 -281.59202)
		(mid 334.80705 -281.871522)
		(end 334.604614 -282.077922)
		(width 0.088646)
		(layer "In4.Cu")
		(net "M_C_CPU0_SA_DQ<4>")
	)
	(arc
		(start 336.938874 -278.017224)
		(mid 336.80796 -278.153584)
		(end 336.760312 -278.336502)
		(width 0.088646)
		(layer "In4.Cu")
		(net "M_C_CPU0_SA_DQ<4>")
	)
	(segment
		(start 281.129994 -313.76239)
		(end 280.73477 -313.76239)
		(width 0.20066)
		(layer "F.Cu")
		(net "M_C_CPU0_SA_DQ<3>")
	)
	(segment
		(start 277.839932 -314.19165)
		(end 277.601934 -314.19165)
		(width 0.101854)
		(layer "F.Cu")
		(net "M_C_CPU0_SA_DQ<3>")
	)
	(segment
		(start 280.606246 -314.042552)
		(end 280.457148 -314.19165)
		(width 0.20066)
		(layer "F.Cu")
		(net "M_C_CPU0_SA_DQ<3>")
	)
	(segment
		(start 277.091394 -314.06338)
		(end 277.091394 -313.892692)
		(width 0.20066)
		(layer "F.Cu")
		(net "M_C_CPU0_SA_DQ<3>")
	)
	(segment
		(start 282.811982 -313.766708)
		(end 281.99588 -313.766708)
		(width 0.20066)
		(layer "F.Cu")
		(net "M_C_CPU0_SA_DQ<3>")
	)
	(segment
		(start 280.606246 -313.890914)
		(end 280.606246 -314.042552)
		(width 0.20066)
		(layer "F.Cu")
		(net "M_C_CPU0_SA_DQ<3>")
	)
	(segment
		(start 276.96541 -313.766708)
		(end 275.268182 -313.766708)
		(width 0.20066)
		(layer "F.Cu")
		(net "M_C_CPU0_SA_DQ<3>")
	)
	(segment
		(start 277.58771 -314.205874)
		(end 277.233888 -314.205874)
		(width 0.20066)
		(layer "F.Cu")
		(net "M_C_CPU0_SA_DQ<3>")
	)
	(segment
		(start 283.916882 -313.766708)
		(end 282.811982 -313.766708)
		(width 0.20066)
		(layer "F.Cu")
		(net "M_C_CPU0_SA_DQ<3>")
	)
	(segment
		(start 277.601934 -314.19165)
		(end 277.58771 -314.205874)
		(width 0.101854)
		(layer "F.Cu")
		(net "M_C_CPU0_SA_DQ<3>")
	)
	(segment
		(start 280.73477 -313.76239)
		(end 280.606246 -313.890914)
		(width 0.20066)
		(layer "F.Cu")
		(net "M_C_CPU0_SA_DQ<3>")
	)
	(segment
		(start 277.233888 -314.205874)
		(end 277.091394 -314.06338)
		(width 0.20066)
		(layer "F.Cu")
		(net "M_C_CPU0_SA_DQ<3>")
	)
	(segment
		(start 277.091394 -313.892692)
		(end 276.96541 -313.766708)
		(width 0.20066)
		(layer "F.Cu")
		(net "M_C_CPU0_SA_DQ<3>")
	)
	(segment
		(start 281.99588 -313.766708)
		(end 281.788362 -313.974226)
		(width 0.20066)
		(layer "F.Cu")
		(net "M_C_CPU0_SA_DQ<3>")
	)
	(segment
		(start 341.833962 -277.800562)
		(end 341.833962 -278.336248)
		(width 0.20066)
		(layer "F.Cu")
		(net "M_C_CPU0_SA_DQ<3>")
	)
	(segment
		(start 280.457148 -314.19165)
		(end 279.912826 -314.19165)
		(width 0.20066)
		(layer "F.Cu")
		(net "M_C_CPU0_SA_DQ<3>")
	)
	(segment
		(start 341.833962 -278.336248)
		(end 341.834216 -278.336502)
		(width 0.20066)
		(layer "F.Cu")
		(net "M_C_CPU0_SA_DQ<3>")
	)
	(segment
		(start 281.34183 -313.974226)
		(end 281.129994 -313.76239)
		(width 0.20066)
		(layer "F.Cu")
		(net "M_C_CPU0_SA_DQ<3>")
	)
	(segment
		(start 281.788362 -313.974226)
		(end 281.34183 -313.974226)
		(width 0.20066)
		(layer "F.Cu")
		(net "M_C_CPU0_SA_DQ<3>")
	)
	(segment
		(start 279.912826 -314.19165)
		(end 277.839932 -314.19165)
		(width 0.1016)
		(layer "F.Cu")
		(net "M_C_CPU0_SA_DQ<3>")
	)
	(segment
		(start 306.971192 -313.952636)
		(end 305.762152 -313.952636)
		(width 0.18288)
		(layer "In4.Cu")
		(net "M_C_CPU0_SA_DQ<3>")
	)
	(segment
		(start 308.32044 -313.410092)
		(end 308.32044 -313.669172)
		(width 0.18288)
		(layer "In4.Cu")
		(net "M_C_CPU0_SA_DQ<3>")
	)
	(segment
		(start 300.93285 -315.614558)
		(end 300.93285 -315.839348)
		(width 0.18288)
		(layer "In4.Cu")
		(net "M_C_CPU0_SA_DQ<3>")
	)
	(segment
		(start 303.410112 -315.184536)
		(end 302.59528 -315.999368)
		(width 0.18288)
		(layer "In4.Cu")
		(net "M_C_CPU0_SA_DQ<3>")
	)
	(segment
		(start 339.195918 -279.63622)
		(end 339.202014 -279.639776)
		(width 0.088646)
		(layer "In4.Cu")
		(net "M_C_CPU0_SA_DQ<3>")
	)
	(segment
		(start 308.32044 -313.669172)
		(end 308.722014 -314.070746)
		(width 0.18288)
		(layer "In4.Cu")
		(net "M_C_CPU0_SA_DQ<3>")
	)
	(segment
		(start 299.27423 -316.74181)
		(end 294.160194 -316.74181)
		(width 0.18288)
		(layer "In4.Cu")
		(net "M_C_CPU0_SA_DQ<3>")
	)
	(segment
		(start 287.708594 -314.355226)
		(end 284.5054 -314.355226)
		(width 0.18288)
		(layer "In4.Cu")
		(net "M_C_CPU0_SA_DQ<3>")
	)
	(segment
		(start 335.92135 -285.980632)
		(end 335.91246 -285.985712)
		(width 0.088646)
		(layer "In4.Cu")
		(net "M_C_CPU0_SA_DQ<3>")
	)
	(segment
		(start 338.732114 -282.730194)
		(end 338.73186 -282.730194)
		(width 0.088646)
		(layer "In4.Cu")
		(net "M_C_CPU0_SA_DQ<3>")
	)
	(segment
		(start 338.726018 -282.077922)
		(end 338.732114 -282.081478)
		(width 0.088646)
		(layer "In4.Cu")
		(net "M_C_CPU0_SA_DQ<3>")
	)
	(segment
		(start 294.160194 -316.74181)
		(end 293.438072 -316.019688)
		(width 0.18288)
		(layer "In4.Cu")
		(net "M_C_CPU0_SA_DQ<3>")
	)
	(segment
		(start 307.805582 -314.787026)
		(end 306.971192 -313.952636)
		(width 0.18288)
		(layer "In4.Cu")
		(net "M_C_CPU0_SA_DQ<3>")
	)
	(segment
		(start 336.852514 -284.35808)
		(end 336.846418 -284.361636)
		(width 0.088646)
		(layer "In4.Cu")
		(net "M_C_CPU0_SA_DQ<3>")
	)
	(segment
		(start 301.78375 -315.999368)
		(end 301.62373 -315.839348)
		(width 0.18288)
		(layer "In4.Cu")
		(net "M_C_CPU0_SA_DQ<3>")
	)
	(segment
		(start 339.210904 -280.283412)
		(end 339.202014 -280.288492)
		(width 0.088646)
		(layer "In4.Cu")
		(net "M_C_CPU0_SA_DQ<3>")
	)
	(segment
		(start 300.016672 -315.999368)
		(end 299.27423 -316.74181)
		(width 0.18288)
		(layer "In4.Cu")
		(net "M_C_CPU0_SA_DQ<3>")
	)
	(segment
		(start 305.762152 -313.952636)
		(end 304.530252 -315.184536)
		(width 0.18288)
		(layer "In4.Cu")
		(net "M_C_CPU0_SA_DQ<3>")
	)
	(segment
		(start 308.722014 -314.070746)
		(end 308.722014 -314.312554)
		(width 0.18288)
		(layer "In4.Cu")
		(net "M_C_CPU0_SA_DQ<3>")
	)
	(segment
		(start 301.09287 -315.454538)
		(end 300.93285 -315.614558)
		(width 0.18288)
		(layer "In4.Cu")
		(net "M_C_CPU0_SA_DQ<3>")
	)
	(segment
		(start 308.566566 -313.163966)
		(end 308.32044 -313.410092)
		(width 0.18288)
		(layer "In4.Cu")
		(net "M_C_CPU0_SA_DQ<3>")
	)
	(segment
		(start 300.93285 -315.839348)
		(end 300.77283 -315.999368)
		(width 0.18288)
		(layer "In4.Cu")
		(net "M_C_CPU0_SA_DQ<3>")
	)
	(segment
		(start 301.62373 -315.839348)
		(end 301.62373 -315.637418)
		(width 0.18288)
		(layer "In4.Cu")
		(net "M_C_CPU0_SA_DQ<3>")
	)
	(segment
		(start 309.453534 -313.581034)
		(end 309.209694 -313.581034)
		(width 0.18288)
		(layer "In4.Cu")
		(net "M_C_CPU0_SA_DQ<3>")
	)
	(segment
		(start 314.90031 -312.15457)
		(end 313.040522 -312.924698)
		(width 0.18288)
		(layer "In4.Cu")
		(net "M_C_CPU0_SA_DQ<3>")
	)
	(segment
		(start 313.040522 -312.924698)
		(end 312.458862 -313.506358)
		(width 0.18288)
		(layer "In4.Cu")
		(net "M_C_CPU0_SA_DQ<3>")
	)
	(segment
		(start 340.156546 -278.02078)
		(end 340.141814 -278.012144)
		(width 0.088646)
		(layer "In4.Cu")
		(net "M_C_CPU0_SA_DQ<3>")
	)
	(segment
		(start 284.5054 -314.355226)
		(end 283.916882 -313.766708)
		(width 0.18288)
		(layer "In4.Cu")
		(net "M_C_CPU0_SA_DQ<3>")
	)
	(segment
		(start 308.722014 -314.312554)
		(end 308.247542 -314.787026)
		(width 0.18288)
		(layer "In4.Cu")
		(net "M_C_CPU0_SA_DQ<3>")
	)
	(segment
		(start 291.733224 -315.891672)
		(end 289.24504 -315.891672)
		(width 0.18288)
		(layer "In4.Cu")
		(net "M_C_CPU0_SA_DQ<3>")
	)
	(segment
		(start 337.039712 -284.023816)
		(end 337.039712 -284.042358)
		(width 0.088646)
		(layer "In4.Cu")
		(net "M_C_CPU0_SA_DQ<3>")
	)
	(segment
		(start 339.21065 -278.65578)
		(end 339.20176 -278.66086)
		(width 0.088646)
		(layer "In4.Cu")
		(net "M_C_CPU0_SA_DQ<3>")
	)
	(segment
		(start 309.209694 -313.581034)
		(end 308.792626 -313.163966)
		(width 0.18288)
		(layer "In4.Cu")
		(net "M_C_CPU0_SA_DQ<3>")
	)
	(segment
		(start 338.919312 -279.140412)
		(end 338.919312 -279.150318)
		(width 0.088646)
		(layer "In4.Cu")
		(net "M_C_CPU0_SA_DQ<3>")
	)
	(segment
		(start 338.732114 -282.081478)
		(end 338.741004 -282.086558)
		(width 0.088646)
		(layer "In4.Cu")
		(net "M_C_CPU0_SA_DQ<3>")
	)
	(segment
		(start 339.202014 -279.639776)
		(end 339.210904 -279.644856)
		(width 0.088646)
		(layer "In4.Cu")
		(net "M_C_CPU0_SA_DQ<3>")
	)
	(segment
		(start 292.042342 -316.019688)
		(end 291.733224 -315.891672)
		(width 0.18288)
		(layer "In4.Cu")
		(net "M_C_CPU0_SA_DQ<3>")
	)
	(segment
		(start 332.884526 -287.044892)
		(end 332.584552 -287.044892)
		(width 0.18288)
		(layer "In4.Cu")
		(net "M_C_CPU0_SA_DQ<3>")
	)
	(segment
		(start 301.44085 -315.454538)
		(end 301.09287 -315.454538)
		(width 0.18288)
		(layer "In4.Cu")
		(net "M_C_CPU0_SA_DQ<3>")
	)
	(segment
		(start 320.423032 -304.508662)
		(end 320.423032 -306.631848)
		(width 0.18288)
		(layer "In4.Cu")
		(net "M_C_CPU0_SA_DQ<3>")
	)
	(segment
		(start 308.247542 -314.787026)
		(end 307.805582 -314.787026)
		(width 0.18288)
		(layer "In4.Cu")
		(net "M_C_CPU0_SA_DQ<3>")
	)
	(segment
		(start 300.77283 -315.999368)
		(end 300.016672 -315.999368)
		(width 0.18288)
		(layer "In4.Cu")
		(net "M_C_CPU0_SA_DQ<3>")
	)
	(segment
		(start 338.449412 -281.582114)
		(end 338.449412 -281.59202)
		(width 0.088646)
		(layer "In4.Cu")
		(net "M_C_CPU0_SA_DQ<3>")
	)
	(segment
		(start 293.438072 -316.019688)
		(end 292.042342 -316.019688)
		(width 0.18288)
		(layer "In4.Cu")
		(net "M_C_CPU0_SA_DQ<3>")
	)
	(segment
		(start 310.201056 -312.833512)
		(end 309.453534 -313.581034)
		(width 0.18288)
		(layer "In4.Cu")
		(net "M_C_CPU0_SA_DQ<3>")
	)
	(segment
		(start 338.449412 -283.205682)
		(end 338.449412 -283.219906)
		(width 0.088646)
		(layer "In4.Cu")
		(net "M_C_CPU0_SA_DQ<3>")
	)
	(segment
		(start 339.767418 -278.012144)
		(end 339.767164 -278.012398)
		(width 0.088646)
		(layer "In4.Cu")
		(net "M_C_CPU0_SA_DQ<3>")
	)
	(segment
		(start 310.677814 -312.833512)
		(end 310.201056 -312.833512)
		(width 0.18288)
		(layer "In4.Cu")
		(net "M_C_CPU0_SA_DQ<3>")
	)
	(segment
		(start 320.423032 -306.631848)
		(end 314.90031 -312.15457)
		(width 0.18288)
		(layer "In4.Cu")
		(net "M_C_CPU0_SA_DQ<3>")
	)
	(segment
		(start 338.741004 -282.725114)
		(end 338.732114 -282.730194)
		(width 0.088646)
		(layer "In4.Cu")
		(net "M_C_CPU0_SA_DQ<3>")
	)
	(segment
		(start 336.39125 -285.166816)
		(end 336.38236 -285.171896)
		(width 0.088646)
		(layer "In4.Cu")
		(net "M_C_CPU0_SA_DQ<3>")
	)
	(segment
		(start 304.530252 -315.184536)
		(end 303.410112 -315.184536)
		(width 0.18288)
		(layer "In4.Cu")
		(net "M_C_CPU0_SA_DQ<3>")
	)
	(segment
		(start 301.62373 -315.637418)
		(end 301.44085 -315.454538)
		(width 0.18288)
		(layer "In4.Cu")
		(net "M_C_CPU0_SA_DQ<3>")
	)
	(segment
		(start 308.792626 -313.163966)
		(end 308.566566 -313.163966)
		(width 0.18288)
		(layer "In4.Cu")
		(net "M_C_CPU0_SA_DQ<3>")
	)
	(segment
		(start 341.394288 -278.129238)
		(end 341.112094 -277.982426)
		(width 0.088646)
		(layer "In4.Cu")
		(net "M_C_CPU0_SA_DQ<3>")
	)
	(segment
		(start 336.099912 -285.651448)
		(end 336.099912 -285.661354)
		(width 0.088646)
		(layer "In4.Cu")
		(net "M_C_CPU0_SA_DQ<3>")
	)
	(segment
		(start 327.329292 -297.602402)
		(end 320.423032 -304.508662)
		(width 0.18288)
		(layer "In4.Cu")
		(net "M_C_CPU0_SA_DQ<3>")
	)
	(segment
		(start 338.27085 -283.539184)
		(end 338.26196 -283.544264)
		(width 0.088646)
		(layer "In4.Cu")
		(net "M_C_CPU0_SA_DQ<3>")
	)
	(segment
		(start 338.74075 -281.097482)
		(end 338.73186 -281.102562)
		(width 0.088646)
		(layer "In4.Cu")
		(net "M_C_CPU0_SA_DQ<3>")
	)
	(segment
		(start 339.579966 -278.336502)
		(end 339.359748 -278.482044)
		(width 0.088646)
		(layer "In4.Cu")
		(net "M_C_CPU0_SA_DQ<3>")
	)
	(segment
		(start 332.584552 -287.044892)
		(end 331.080364 -288.54908)
		(width 0.18288)
		(layer "In4.Cu")
		(net "M_C_CPU0_SA_DQ<3>")
	)
	(segment
		(start 338.919312 -280.76398)
		(end 338.919312 -280.778204)
		(width 0.088646)
		(layer "In4.Cu")
		(net "M_C_CPU0_SA_DQ<3>")
	)
	(segment
		(start 311.35066 -313.506358)
		(end 310.677814 -312.833512)
		(width 0.18288)
		(layer "In4.Cu")
		(net "M_C_CPU0_SA_DQ<3>")
	)
	(segment
		(start 333.750412 -286.456882)
		(end 333.750412 -286.475424)
		(width 0.088646)
		(layer "In4.Cu")
		(net "M_C_CPU0_SA_DQ<3>")
	)
	(segment
		(start 331.080364 -288.54908)
		(end 327.329292 -297.602402)
		(width 0.18288)
		(layer "In4.Cu")
		(net "M_C_CPU0_SA_DQ<3>")
	)
	(segment
		(start 333.180944 -287.044892)
		(end 332.884526 -287.044892)
		(width 0.088646)
		(layer "In4.Cu")
		(net "M_C_CPU0_SA_DQ<3>")
	)
	(segment
		(start 333.375762 -286.850074)
		(end 333.180944 -287.044892)
		(width 0.088646)
		(layer "In4.Cu")
		(net "M_C_CPU0_SA_DQ<3>")
	)
	(segment
		(start 289.24504 -315.891672)
		(end 287.708594 -314.355226)
		(width 0.18288)
		(layer "In4.Cu")
		(net "M_C_CPU0_SA_DQ<3>")
	)
	(segment
		(start 312.458862 -313.506358)
		(end 311.35066 -313.506358)
		(width 0.18288)
		(layer "In4.Cu")
		(net "M_C_CPU0_SA_DQ<3>")
	)
	(segment
		(start 302.59528 -315.999368)
		(end 301.78375 -315.999368)
		(width 0.18288)
		(layer "In4.Cu")
		(net "M_C_CPU0_SA_DQ<3>")
	)
	(arc
		(start 334.97266 -285.985712)
		(mid 334.785462 -286.035855)
		(end 334.598264 -285.985712)
		(width 0.088646)
		(layer "In4.Cu")
		(net "M_C_CPU0_SA_DQ<3>")
	)
	(arc
		(start 334.03286 -285.985712)
		(mid 333.830574 -286.184693)
		(end 333.750412 -286.456882)
		(width 0.088646)
		(layer "In4.Cu")
		(net "M_C_CPU0_SA_DQ<3>")
	)
	(arc
		(start 338.449412 -283.219906)
		(mid 338.401733 -283.402806)
		(end 338.27085 -283.539184)
		(width 0.088646)
		(layer "In4.Cu")
		(net "M_C_CPU0_SA_DQ<3>")
	)
	(arc
		(start 338.73186 -281.102562)
		(mid 338.527525 -281.305167)
		(end 338.449412 -281.582114)
		(width 0.088646)
		(layer "In4.Cu")
		(net "M_C_CPU0_SA_DQ<3>")
	)
	(arc
		(start 338.26196 -283.544264)
		(mid 338.074762 -283.594407)
		(end 337.887564 -283.544264)
		(width 0.088646)
		(layer "In4.Cu")
		(net "M_C_CPU0_SA_DQ<3>")
	)
	(arc
		(start 340.141814 -278.012144)
		(mid 339.954616 -277.962001)
		(end 339.767418 -278.012144)
		(width 0.088646)
		(layer "In4.Cu")
		(net "M_C_CPU0_SA_DQ<3>")
	)
	(arc
		(start 338.919312 -280.778204)
		(mid 338.871633 -280.961104)
		(end 338.74075 -281.097482)
		(width 0.088646)
		(layer "In4.Cu")
		(net "M_C_CPU0_SA_DQ<3>")
	)
	(arc
		(start 333.57185 -286.794702)
		(mid 333.47764 -286.835964)
		(end 333.375762 -286.850074)
		(width 0.088646)
		(layer "In4.Cu")
		(net "M_C_CPU0_SA_DQ<3>")
	)
	(arc
		(start 336.569812 -284.847538)
		(mid 336.522133 -285.030438)
		(end 336.39125 -285.166816)
		(width 0.088646)
		(layer "In4.Cu")
		(net "M_C_CPU0_SA_DQ<3>")
	)
	(arc
		(start 336.38236 -285.171896)
		(mid 336.178025 -285.374501)
		(end 336.099912 -285.651448)
		(width 0.088646)
		(layer "In4.Cu")
		(net "M_C_CPU0_SA_DQ<3>")
	)
	(arc
		(start 341.112094 -277.982426)
		(mid 340.867337 -277.929333)
		(end 340.629494 -278.007826)
		(width 0.088646)
		(layer "In4.Cu")
		(net "M_C_CPU0_SA_DQ<3>")
	)
	(arc
		(start 341.834216 -278.336502)
		(mid 341.612209 -278.237206)
		(end 341.394288 -278.129238)
		(width 0.088646)
		(layer "In4.Cu")
		(net "M_C_CPU0_SA_DQ<3>")
	)
	(arc
		(start 337.887564 -283.544264)
		(mid 337.604862 -283.468488)
		(end 337.32216 -283.544264)
		(width 0.088646)
		(layer "In4.Cu")
		(net "M_C_CPU0_SA_DQ<3>")
	)
	(arc
		(start 339.359748 -278.482044)
		(mid 339.298772 -278.580553)
		(end 339.21065 -278.65578)
		(width 0.088646)
		(layer "In4.Cu")
		(net "M_C_CPU0_SA_DQ<3>")
	)
	(arc
		(start 335.91246 -285.985712)
		(mid 335.725262 -286.035855)
		(end 335.538064 -285.985712)
		(width 0.088646)
		(layer "In4.Cu")
		(net "M_C_CPU0_SA_DQ<3>")
	)
	(arc
		(start 335.538064 -285.985712)
		(mid 335.255362 -285.90997)
		(end 334.97266 -285.985712)
		(width 0.088646)
		(layer "In4.Cu")
		(net "M_C_CPU0_SA_DQ<3>")
	)
	(arc
		(start 340.629494 -278.007826)
		(mid 340.39487 -278.082027)
		(end 340.156546 -278.02078)
		(width 0.088646)
		(layer "In4.Cu")
		(net "M_C_CPU0_SA_DQ<3>")
	)
	(arc
		(start 336.099912 -285.661354)
		(mid 336.052233 -285.844254)
		(end 335.92135 -285.980632)
		(width 0.088646)
		(layer "In4.Cu")
		(net "M_C_CPU0_SA_DQ<3>")
	)
	(arc
		(start 337.039712 -284.042358)
		(mid 336.987442 -284.224723)
		(end 336.852514 -284.35808)
		(width 0.088646)
		(layer "In4.Cu")
		(net "M_C_CPU0_SA_DQ<3>")
	)
	(arc
		(start 338.73186 -282.730194)
		(mid 338.528555 -282.93106)
		(end 338.449412 -283.205682)
		(width 0.088646)
		(layer "In4.Cu")
		(net "M_C_CPU0_SA_DQ<3>")
	)
	(arc
		(start 338.919312 -279.150318)
		(mid 338.993303 -279.429884)
		(end 339.195918 -279.63622)
		(width 0.088646)
		(layer "In4.Cu")
		(net "M_C_CPU0_SA_DQ<3>")
	)
	(arc
		(start 339.202014 -280.288492)
		(mid 338.998533 -280.489296)
		(end 338.919312 -280.76398)
		(width 0.088646)
		(layer "In4.Cu")
		(net "M_C_CPU0_SA_DQ<3>")
	)
	(arc
		(start 334.598264 -285.985712)
		(mid 334.315562 -285.90997)
		(end 334.03286 -285.985712)
		(width 0.088646)
		(layer "In4.Cu")
		(net "M_C_CPU0_SA_DQ<3>")
	)
	(arc
		(start 339.210904 -279.644856)
		(mid 339.389501 -279.964134)
		(end 339.210904 -280.283412)
		(width 0.088646)
		(layer "In4.Cu")
		(net "M_C_CPU0_SA_DQ<3>")
	)
	(arc
		(start 339.20176 -278.66086)
		(mid 338.997425 -278.863465)
		(end 338.919312 -279.140412)
		(width 0.088646)
		(layer "In4.Cu")
		(net "M_C_CPU0_SA_DQ<3>")
	)
	(arc
		(start 337.32216 -283.544264)
		(mid 337.117825 -283.746869)
		(end 337.039712 -284.023816)
		(width 0.088646)
		(layer "In4.Cu")
		(net "M_C_CPU0_SA_DQ<3>")
	)
	(arc
		(start 338.741004 -282.086558)
		(mid 338.919601 -282.405836)
		(end 338.741004 -282.725114)
		(width 0.088646)
		(layer "In4.Cu")
		(net "M_C_CPU0_SA_DQ<3>")
	)
	(arc
		(start 339.767164 -278.012398)
		(mid 339.630119 -278.149358)
		(end 339.579966 -278.336502)
		(width 0.088646)
		(layer "In4.Cu")
		(net "M_C_CPU0_SA_DQ<3>")
	)
	(arc
		(start 338.449412 -281.59202)
		(mid 338.523403 -281.871586)
		(end 338.726018 -282.077922)
		(width 0.088646)
		(layer "In4.Cu")
		(net "M_C_CPU0_SA_DQ<3>")
	)
	(arc
		(start 336.846418 -284.361636)
		(mid 336.643831 -284.567987)
		(end 336.569812 -284.847538)
		(width 0.088646)
		(layer "In4.Cu")
		(net "M_C_CPU0_SA_DQ<3>")
	)
	(arc
		(start 333.750412 -286.475424)
		(mid 333.702733 -286.658324)
		(end 333.57185 -286.794702)
		(width 0.088646)
		(layer "In4.Cu")
		(net "M_C_CPU0_SA_DQ<3>")
	)
	(segment
		(start 280.606246 -279.890982)
		(end 280.606246 -280.04262)
		(width 0.20066)
		(layer "F.Cu")
		(net "M_C_CPU0_SA_DQ<31>")
	)
	(segment
		(start 277.601934 -280.191718)
		(end 277.58771 -280.205942)
		(width 0.101854)
		(layer "F.Cu")
		(net "M_C_CPU0_SA_DQ<31>")
	)
	(segment
		(start 277.091394 -279.89276)
		(end 276.96541 -279.766776)
		(width 0.20066)
		(layer "F.Cu")
		(net "M_C_CPU0_SA_DQ<31>")
	)
	(segment
		(start 281.34183 -279.974294)
		(end 281.129994 -279.762458)
		(width 0.20066)
		(layer "F.Cu")
		(net "M_C_CPU0_SA_DQ<31>")
	)
	(segment
		(start 277.839932 -280.191718)
		(end 277.601934 -280.191718)
		(width 0.101854)
		(layer "F.Cu")
		(net "M_C_CPU0_SA_DQ<31>")
	)
	(segment
		(start 280.606246 -280.04262)
		(end 280.457148 -280.191718)
		(width 0.20066)
		(layer "F.Cu")
		(net "M_C_CPU0_SA_DQ<31>")
	)
	(segment
		(start 344.653362 -263.150604)
		(end 344.653362 -263.68629)
		(width 0.20066)
		(layer "F.Cu")
		(net "M_C_CPU0_SA_DQ<31>")
	)
	(segment
		(start 280.457148 -280.191718)
		(end 279.912826 -280.191718)
		(width 0.20066)
		(layer "F.Cu")
		(net "M_C_CPU0_SA_DQ<31>")
	)
	(segment
		(start 283.916882 -279.766776)
		(end 282.811982 -279.766776)
		(width 0.20066)
		(layer "F.Cu")
		(net "M_C_CPU0_SA_DQ<31>")
	)
	(segment
		(start 279.912826 -280.191718)
		(end 277.839932 -280.191718)
		(width 0.1016)
		(layer "F.Cu")
		(net "M_C_CPU0_SA_DQ<31>")
	)
	(segment
		(start 277.58771 -280.205942)
		(end 277.233888 -280.205942)
		(width 0.20066)
		(layer "F.Cu")
		(net "M_C_CPU0_SA_DQ<31>")
	)
	(segment
		(start 277.233888 -280.205942)
		(end 277.091394 -280.063448)
		(width 0.20066)
		(layer "F.Cu")
		(net "M_C_CPU0_SA_DQ<31>")
	)
	(segment
		(start 276.96541 -279.766776)
		(end 275.268182 -279.766776)
		(width 0.20066)
		(layer "F.Cu")
		(net "M_C_CPU0_SA_DQ<31>")
	)
	(segment
		(start 344.653362 -263.68629)
		(end 344.653616 -263.686544)
		(width 0.20066)
		(layer "F.Cu")
		(net "M_C_CPU0_SA_DQ<31>")
	)
	(segment
		(start 281.129994 -279.762458)
		(end 280.73477 -279.762458)
		(width 0.20066)
		(layer "F.Cu")
		(net "M_C_CPU0_SA_DQ<31>")
	)
	(segment
		(start 282.811982 -279.766776)
		(end 281.99588 -279.766776)
		(width 0.20066)
		(layer "F.Cu")
		(net "M_C_CPU0_SA_DQ<31>")
	)
	(segment
		(start 280.73477 -279.762458)
		(end 280.606246 -279.890982)
		(width 0.20066)
		(layer "F.Cu")
		(net "M_C_CPU0_SA_DQ<31>")
	)
	(segment
		(start 281.99588 -279.766776)
		(end 281.788362 -279.974294)
		(width 0.20066)
		(layer "F.Cu")
		(net "M_C_CPU0_SA_DQ<31>")
	)
	(segment
		(start 277.091394 -280.063448)
		(end 277.091394 -279.89276)
		(width 0.20066)
		(layer "F.Cu")
		(net "M_C_CPU0_SA_DQ<31>")
	)
	(segment
		(start 281.788362 -279.974294)
		(end 281.34183 -279.974294)
		(width 0.20066)
		(layer "F.Cu")
		(net "M_C_CPU0_SA_DQ<31>")
	)
	(segment
		(start 296.211244 -276.286722)
		(end 295.86555 -276.286722)
		(width 0.18288)
		(layer "In6.Cu")
		(net "M_C_CPU0_SA_DQ<31>")
	)
	(segment
		(start 285.955486 -279.109932)
		(end 285.955486 -278.686514)
		(width 0.18288)
		(layer "In6.Cu")
		(net "M_C_CPU0_SA_DQ<31>")
	)
	(segment
		(start 336.852514 -263.196832)
		(end 336.846672 -263.200388)
		(width 0.088646)
		(layer "In6.Cu")
		(net "M_C_CPU0_SA_DQ<31>")
	)
	(segment
		(start 336.477864 -263.197086)
		(end 336.477864 -263.196832)
		(width 0.088646)
		(layer "In6.Cu")
		(net "M_C_CPU0_SA_DQ<31>")
	)
	(segment
		(start 344.340688 -263.686544)
		(end 344.274902 -263.620758)
		(width 0.088646)
		(layer "In6.Cu")
		(net "M_C_CPU0_SA_DQ<31>")
	)
	(segment
		(start 290.3855 -278.437086)
		(end 288.920174 -278.437086)
		(width 0.18288)
		(layer "In6.Cu")
		(net "M_C_CPU0_SA_DQ<31>")
	)
	(segment
		(start 342.497156 -263.19353)
		(end 342.491314 -263.196832)
		(width 0.088646)
		(layer "In6.Cu")
		(net "M_C_CPU0_SA_DQ<31>")
	)
	(segment
		(start 331.945234 -264.01903)
		(end 331.245464 -264.7188)
		(width 0.088646)
		(layer "In6.Cu")
		(net "M_C_CPU0_SA_DQ<31>")
	)
	(segment
		(start 302.931322 -273.388582)
		(end 301.508922 -273.388582)
		(width 0.18288)
		(layer "In6.Cu")
		(net "M_C_CPU0_SA_DQ<31>")
	)
	(segment
		(start 287.337246 -278.686514)
		(end 287.154366 -278.503634)
		(width 0.18288)
		(layer "In6.Cu")
		(net "M_C_CPU0_SA_DQ<31>")
	)
	(segment
		(start 338.737956 -263.19353)
		(end 338.732114 -263.196832)
		(width 0.088646)
		(layer "In6.Cu")
		(net "M_C_CPU0_SA_DQ<31>")
	)
	(segment
		(start 321.46367 -266.036298)
		(end 317.123826 -267.834364)
		(width 0.18288)
		(layer "In6.Cu")
		(net "M_C_CPU0_SA_DQ<31>")
	)
	(segment
		(start 337.79587 -263.1948)
		(end 337.792314 -263.196832)
		(width 0.088646)
		(layer "In6.Cu")
		(net "M_C_CPU0_SA_DQ<31>")
	)
	(segment
		(start 341.557356 -263.19353)
		(end 341.551514 -263.196832)
		(width 0.088646)
		(layer "In6.Cu")
		(net "M_C_CPU0_SA_DQ<31>")
	)
	(segment
		(start 340.611714 -263.196832)
		(end 340.605872 -263.200388)
		(width 0.088646)
		(layer "In6.Cu")
		(net "M_C_CPU0_SA_DQ<31>")
	)
	(segment
		(start 290.78428 -278.038306)
		(end 290.3855 -278.437086)
		(width 0.18288)
		(layer "In6.Cu")
		(net "M_C_CPU0_SA_DQ<31>")
	)
	(segment
		(start 332.44663 -263.204706)
		(end 332.255876 -263.282684)
		(width 0.088646)
		(layer "In6.Cu")
		(net "M_C_CPU0_SA_DQ<31>")
	)
	(segment
		(start 298.806616 -275.091652)
		(end 298.806362 -275.091398)
		(width 0.18288)
		(layer "In6.Cu")
		(net "M_C_CPU0_SA_DQ<31>")
	)
	(segment
		(start 295.86555 -276.286722)
		(end 295.520364 -275.941536)
		(width 0.18288)
		(layer "In6.Cu")
		(net "M_C_CPU0_SA_DQ<31>")
	)
	(segment
		(start 326.70369 -266.036298)
		(end 321.46367 -266.036298)
		(width 0.18288)
		(layer "In6.Cu")
		(net "M_C_CPU0_SA_DQ<31>")
	)
	(segment
		(start 338.732114 -263.196832)
		(end 338.726272 -263.200388)
		(width 0.088646)
		(layer "In6.Cu")
		(net "M_C_CPU0_SA_DQ<31>")
	)
	(segment
		(start 299.284644 -275.091652)
		(end 298.806616 -275.091652)
		(width 0.18288)
		(layer "In6.Cu")
		(net "M_C_CPU0_SA_DQ<31>")
	)
	(segment
		(start 311.348882 -271.835626)
		(end 310.640476 -272.544032)
		(width 0.18288)
		(layer "In6.Cu")
		(net "M_C_CPU0_SA_DQ<31>")
	)
	(segment
		(start 296.55643 -275.941536)
		(end 296.211244 -276.286722)
		(width 0.18288)
		(layer "In6.Cu")
		(net "M_C_CPU0_SA_DQ<31>")
	)
	(segment
		(start 303.775872 -272.544032)
		(end 302.931322 -273.388582)
		(width 0.18288)
		(layer "In6.Cu")
		(net "M_C_CPU0_SA_DQ<31>")
	)
	(segment
		(start 287.520126 -279.292812)
		(end 287.337246 -279.109932)
		(width 0.18288)
		(layer "In6.Cu")
		(net "M_C_CPU0_SA_DQ<31>")
	)
	(segment
		(start 340.617556 -263.19353)
		(end 340.611714 -263.196832)
		(width 0.088646)
		(layer "In6.Cu")
		(net "M_C_CPU0_SA_DQ<31>")
	)
	(segment
		(start 291.984176 -275.941536)
		(end 290.78428 -277.141432)
		(width 0.18288)
		(layer "In6.Cu")
		(net "M_C_CPU0_SA_DQ<31>")
	)
	(segment
		(start 290.78428 -277.141432)
		(end 290.78428 -278.038306)
		(width 0.18288)
		(layer "In6.Cu")
		(net "M_C_CPU0_SA_DQ<31>")
	)
	(segment
		(start 304.633376 -272.544032)
		(end 303.775872 -272.544032)
		(width 0.18288)
		(layer "In6.Cu")
		(net "M_C_CPU0_SA_DQ<31>")
	)
	(segment
		(start 343.436956 -263.19353)
		(end 343.431114 -263.196832)
		(width 0.088646)
		(layer "In6.Cu")
		(net "M_C_CPU0_SA_DQ<31>")
	)
	(segment
		(start 286.463486 -279.292812)
		(end 286.138366 -279.292812)
		(width 0.18288)
		(layer "In6.Cu")
		(net "M_C_CPU0_SA_DQ<31>")
	)
	(segment
		(start 308.634892 -272.242026)
		(end 308.332886 -272.544032)
		(width 0.18288)
		(layer "In6.Cu")
		(net "M_C_CPU0_SA_DQ<31>")
	)
	(segment
		(start 305.507136 -273.248374)
		(end 305.324256 -273.431254)
		(width 0.18288)
		(layer "In6.Cu")
		(net "M_C_CPU0_SA_DQ<31>")
	)
	(segment
		(start 305.507136 -272.726912)
		(end 305.507136 -273.248374)
		(width 0.18288)
		(layer "In6.Cu")
		(net "M_C_CPU0_SA_DQ<31>")
	)
	(segment
		(start 298.806362 -275.091398)
		(end 298.049188 -275.091398)
		(width 0.18288)
		(layer "In6.Cu")
		(net "M_C_CPU0_SA_DQ<31>")
	)
	(segment
		(start 297.19905 -275.941536)
		(end 296.55643 -275.941536)
		(width 0.18288)
		(layer "In6.Cu")
		(net "M_C_CPU0_SA_DQ<31>")
	)
	(segment
		(start 339.677756 -263.19353)
		(end 339.671914 -263.196832)
		(width 0.088646)
		(layer "In6.Cu")
		(net "M_C_CPU0_SA_DQ<31>")
	)
	(segment
		(start 304.999136 -273.431254)
		(end 304.816256 -273.248374)
		(width 0.18288)
		(layer "In6.Cu")
		(net "M_C_CPU0_SA_DQ<31>")
	)
	(segment
		(start 299.806106 -275.091398)
		(end 299.284898 -275.091398)
		(width 0.18288)
		(layer "In6.Cu")
		(net "M_C_CPU0_SA_DQ<31>")
	)
	(segment
		(start 285.772606 -278.503634)
		(end 285.447486 -278.503634)
		(width 0.18288)
		(layer "In6.Cu")
		(net "M_C_CPU0_SA_DQ<31>")
	)
	(segment
		(start 313.683904 -270.831056)
		(end 312.679334 -271.835626)
		(width 0.18288)
		(layer "In6.Cu")
		(net "M_C_CPU0_SA_DQ<31>")
	)
	(segment
		(start 298.049188 -275.091398)
		(end 297.19905 -275.941536)
		(width 0.18288)
		(layer "In6.Cu")
		(net "M_C_CPU0_SA_DQ<31>")
	)
	(segment
		(start 286.646366 -278.686514)
		(end 286.646366 -279.109932)
		(width 0.18288)
		(layer "In6.Cu")
		(net "M_C_CPU0_SA_DQ<31>")
	)
	(segment
		(start 332.18247 -263.331452)
		(end 331.945234 -263.568688)
		(width 0.088646)
		(layer "In6.Cu")
		(net "M_C_CPU0_SA_DQ<31>")
	)
	(segment
		(start 330.979272 -264.7188)
		(end 329.884786 -264.7188)
		(width 0.18288)
		(layer "In6.Cu")
		(net "M_C_CPU0_SA_DQ<31>")
	)
	(segment
		(start 341.551514 -263.196832)
		(end 341.545672 -263.200388)
		(width 0.088646)
		(layer "In6.Cu")
		(net "M_C_CPU0_SA_DQ<31>")
	)
	(segment
		(start 284.390846 -279.292812)
		(end 283.916882 -279.766776)
		(width 0.18288)
		(layer "In6.Cu")
		(net "M_C_CPU0_SA_DQ<31>")
	)
	(segment
		(start 331.245464 -264.7188)
		(end 330.979272 -264.7188)
		(width 0.088646)
		(layer "In6.Cu")
		(net "M_C_CPU0_SA_DQ<31>")
	)
	(segment
		(start 309.023766 -272.242026)
		(end 308.634892 -272.242026)
		(width 0.18288)
		(layer "In6.Cu")
		(net "M_C_CPU0_SA_DQ<31>")
	)
	(segment
		(start 285.264606 -278.686514)
		(end 285.264606 -279.109932)
		(width 0.18288)
		(layer "In6.Cu")
		(net "M_C_CPU0_SA_DQ<31>")
	)
	(segment
		(start 286.829246 -278.503634)
		(end 286.646366 -278.686514)
		(width 0.18288)
		(layer "In6.Cu")
		(net "M_C_CPU0_SA_DQ<31>")
	)
	(segment
		(start 299.284898 -275.091398)
		(end 299.284644 -275.091652)
		(width 0.18288)
		(layer "In6.Cu")
		(net "M_C_CPU0_SA_DQ<31>")
	)
	(segment
		(start 295.520364 -275.941536)
		(end 291.984176 -275.941536)
		(width 0.18288)
		(layer "In6.Cu")
		(net "M_C_CPU0_SA_DQ<31>")
	)
	(segment
		(start 342.491314 -263.196832)
		(end 342.485472 -263.200388)
		(width 0.088646)
		(layer "In6.Cu")
		(net "M_C_CPU0_SA_DQ<31>")
	)
	(segment
		(start 343.431114 -263.196832)
		(end 343.425272 -263.200388)
		(width 0.088646)
		(layer "In6.Cu")
		(net "M_C_CPU0_SA_DQ<31>")
	)
	(segment
		(start 288.920174 -278.437086)
		(end 288.064448 -279.292812)
		(width 0.18288)
		(layer "In6.Cu")
		(net "M_C_CPU0_SA_DQ<31>")
	)
	(segment
		(start 304.816256 -273.248374)
		(end 304.816256 -272.726912)
		(width 0.18288)
		(layer "In6.Cu")
		(net "M_C_CPU0_SA_DQ<31>")
	)
	(segment
		(start 329.884786 -264.7188)
		(end 326.70369 -266.036298)
		(width 0.18288)
		(layer "In6.Cu")
		(net "M_C_CPU0_SA_DQ<31>")
	)
	(segment
		(start 285.081726 -279.292812)
		(end 284.390846 -279.292812)
		(width 0.18288)
		(layer "In6.Cu")
		(net "M_C_CPU0_SA_DQ<31>")
	)
	(segment
		(start 304.816256 -272.726912)
		(end 304.633376 -272.544032)
		(width 0.18288)
		(layer "In6.Cu")
		(net "M_C_CPU0_SA_DQ<31>")
	)
	(segment
		(start 317.123826 -267.834364)
		(end 314.127134 -270.831056)
		(width 0.18288)
		(layer "In6.Cu")
		(net "M_C_CPU0_SA_DQ<31>")
	)
	(segment
		(start 286.138366 -279.292812)
		(end 285.955486 -279.109932)
		(width 0.18288)
		(layer "In6.Cu")
		(net "M_C_CPU0_SA_DQ<31>")
	)
	(segment
		(start 288.064448 -279.292812)
		(end 287.520126 -279.292812)
		(width 0.18288)
		(layer "In6.Cu")
		(net "M_C_CPU0_SA_DQ<31>")
	)
	(segment
		(start 287.154366 -278.503634)
		(end 286.829246 -278.503634)
		(width 0.18288)
		(layer "In6.Cu")
		(net "M_C_CPU0_SA_DQ<31>")
	)
	(segment
		(start 308.332886 -272.544032)
		(end 305.690016 -272.544032)
		(width 0.18288)
		(layer "In6.Cu")
		(net "M_C_CPU0_SA_DQ<31>")
	)
	(segment
		(start 310.640476 -272.544032)
		(end 309.325772 -272.544032)
		(width 0.18288)
		(layer "In6.Cu")
		(net "M_C_CPU0_SA_DQ<31>")
	)
	(segment
		(start 331.945234 -263.568688)
		(end 331.945234 -264.01903)
		(width 0.088646)
		(layer "In6.Cu")
		(net "M_C_CPU0_SA_DQ<31>")
	)
	(segment
		(start 285.955486 -278.686514)
		(end 285.772606 -278.503634)
		(width 0.18288)
		(layer "In6.Cu")
		(net "M_C_CPU0_SA_DQ<31>")
	)
	(segment
		(start 305.324256 -273.431254)
		(end 304.999136 -273.431254)
		(width 0.18288)
		(layer "In6.Cu")
		(net "M_C_CPU0_SA_DQ<31>")
	)
	(segment
		(start 301.508922 -273.388582)
		(end 299.806106 -275.091398)
		(width 0.18288)
		(layer "In6.Cu")
		(net "M_C_CPU0_SA_DQ<31>")
	)
	(segment
		(start 309.325772 -272.544032)
		(end 309.023766 -272.242026)
		(width 0.18288)
		(layer "In6.Cu")
		(net "M_C_CPU0_SA_DQ<31>")
	)
	(segment
		(start 344.653616 -263.686544)
		(end 344.340688 -263.686544)
		(width 0.088646)
		(layer "In6.Cu")
		(net "M_C_CPU0_SA_DQ<31>")
	)
	(segment
		(start 339.671914 -263.196832)
		(end 339.666072 -263.200388)
		(width 0.088646)
		(layer "In6.Cu")
		(net "M_C_CPU0_SA_DQ<31>")
	)
	(segment
		(start 314.127134 -270.831056)
		(end 313.683904 -270.831056)
		(width 0.18288)
		(layer "In6.Cu")
		(net "M_C_CPU0_SA_DQ<31>")
	)
	(segment
		(start 305.690016 -272.544032)
		(end 305.507136 -272.726912)
		(width 0.18288)
		(layer "In6.Cu")
		(net "M_C_CPU0_SA_DQ<31>")
	)
	(segment
		(start 287.337246 -279.109932)
		(end 287.337246 -278.686514)
		(width 0.18288)
		(layer "In6.Cu")
		(net "M_C_CPU0_SA_DQ<31>")
	)
	(segment
		(start 312.679334 -271.835626)
		(end 311.348882 -271.835626)
		(width 0.18288)
		(layer "In6.Cu")
		(net "M_C_CPU0_SA_DQ<31>")
	)
	(segment
		(start 285.447486 -278.503634)
		(end 285.264606 -278.686514)
		(width 0.18288)
		(layer "In6.Cu")
		(net "M_C_CPU0_SA_DQ<31>")
	)
	(segment
		(start 285.264606 -279.109932)
		(end 285.081726 -279.292812)
		(width 0.18288)
		(layer "In6.Cu")
		(net "M_C_CPU0_SA_DQ<31>")
	)
	(segment
		(start 336.857086 -263.194292)
		(end 336.852514 -263.196832)
		(width 0.088646)
		(layer "In6.Cu")
		(net "M_C_CPU0_SA_DQ<31>")
	)
	(segment
		(start 286.646366 -279.109932)
		(end 286.463486 -279.292812)
		(width 0.18288)
		(layer "In6.Cu")
		(net "M_C_CPU0_SA_DQ<31>")
	)
	(arc
		(start 336.846672 -263.200388)
		(mid 336.661817 -263.247306)
		(end 336.477864 -263.197086)
		(width 0.088646)
		(layer "In6.Cu")
		(net "M_C_CPU0_SA_DQ<31>")
	)
	(arc
		(start 335.538064 -263.196832)
		(mid 335.255362 -263.12109)
		(end 334.97266 -263.196832)
		(width 0.088646)
		(layer "In6.Cu")
		(net "M_C_CPU0_SA_DQ<31>")
	)
	(arc
		(start 340.605872 -263.200388)
		(mid 340.421017 -263.247306)
		(end 340.237064 -263.197086)
		(width 0.088646)
		(layer "In6.Cu")
		(net "M_C_CPU0_SA_DQ<31>")
	)
	(arc
		(start 340.237064 -263.197086)
		(mid 339.95789 -263.121321)
		(end 339.677756 -263.19353)
		(width 0.088646)
		(layer "In6.Cu")
		(net "M_C_CPU0_SA_DQ<31>")
	)
	(arc
		(start 332.747112 -263.211818)
		(mid 332.597625 -263.176815)
		(end 332.44663 -263.204706)
		(width 0.088646)
		(layer "In6.Cu")
		(net "M_C_CPU0_SA_DQ<31>")
	)
	(arc
		(start 341.545672 -263.200388)
		(mid 341.360817 -263.247306)
		(end 341.176864 -263.197086)
		(width 0.088646)
		(layer "In6.Cu")
		(net "M_C_CPU0_SA_DQ<31>")
	)
	(arc
		(start 333.09306 -263.196832)
		(mid 332.921912 -263.246747)
		(end 332.747112 -263.211818)
		(width 0.088646)
		(layer "In6.Cu")
		(net "M_C_CPU0_SA_DQ<31>")
	)
	(arc
		(start 343.425272 -263.200388)
		(mid 343.240417 -263.247306)
		(end 343.056464 -263.197086)
		(width 0.088646)
		(layer "In6.Cu")
		(net "M_C_CPU0_SA_DQ<31>")
	)
	(arc
		(start 337.417664 -263.196832)
		(mid 337.13772 -263.121188)
		(end 336.857086 -263.194292)
		(width 0.088646)
		(layer "In6.Cu")
		(net "M_C_CPU0_SA_DQ<31>")
	)
	(arc
		(start 337.792314 -263.196832)
		(mid 337.605006 -263.246975)
		(end 337.417664 -263.196832)
		(width 0.088646)
		(layer "In6.Cu")
		(net "M_C_CPU0_SA_DQ<31>")
	)
	(arc
		(start 336.477864 -263.196832)
		(mid 336.195162 -263.12109)
		(end 335.91246 -263.196832)
		(width 0.088646)
		(layer "In6.Cu")
		(net "M_C_CPU0_SA_DQ<31>")
	)
	(arc
		(start 338.726272 -263.200388)
		(mid 338.541417 -263.247306)
		(end 338.357464 -263.197086)
		(width 0.088646)
		(layer "In6.Cu")
		(net "M_C_CPU0_SA_DQ<31>")
	)
	(arc
		(start 334.598264 -263.196832)
		(mid 334.315562 -263.12109)
		(end 334.03286 -263.196832)
		(width 0.088646)
		(layer "In6.Cu")
		(net "M_C_CPU0_SA_DQ<31>")
	)
	(arc
		(start 335.91246 -263.196832)
		(mid 335.725262 -263.246975)
		(end 335.538064 -263.196832)
		(width 0.088646)
		(layer "In6.Cu")
		(net "M_C_CPU0_SA_DQ<31>")
	)
	(arc
		(start 339.297264 -263.197086)
		(mid 339.01809 -263.121321)
		(end 338.737956 -263.19353)
		(width 0.088646)
		(layer "In6.Cu")
		(net "M_C_CPU0_SA_DQ<31>")
	)
	(arc
		(start 343.056464 -263.197086)
		(mid 342.77729 -263.121321)
		(end 342.497156 -263.19353)
		(width 0.088646)
		(layer "In6.Cu")
		(net "M_C_CPU0_SA_DQ<31>")
	)
	(arc
		(start 341.176864 -263.197086)
		(mid 340.89769 -263.121321)
		(end 340.617556 -263.19353)
		(width 0.088646)
		(layer "In6.Cu")
		(net "M_C_CPU0_SA_DQ<31>")
	)
	(arc
		(start 334.97266 -263.196832)
		(mid 334.785462 -263.246975)
		(end 334.598264 -263.196832)
		(width 0.088646)
		(layer "In6.Cu")
		(net "M_C_CPU0_SA_DQ<31>")
	)
	(arc
		(start 332.255876 -263.282684)
		(mid 332.216745 -263.303412)
		(end 332.18247 -263.331452)
		(width 0.088646)
		(layer "In6.Cu")
		(net "M_C_CPU0_SA_DQ<31>")
	)
	(arc
		(start 339.666072 -263.200388)
		(mid 339.481217 -263.247306)
		(end 339.297264 -263.197086)
		(width 0.088646)
		(layer "In6.Cu")
		(net "M_C_CPU0_SA_DQ<31>")
	)
	(arc
		(start 334.03286 -263.196832)
		(mid 333.845662 -263.246975)
		(end 333.658464 -263.196832)
		(width 0.088646)
		(layer "In6.Cu")
		(net "M_C_CPU0_SA_DQ<31>")
	)
	(arc
		(start 338.357464 -263.197086)
		(mid 338.076983 -263.121314)
		(end 337.79587 -263.1948)
		(width 0.088646)
		(layer "In6.Cu")
		(net "M_C_CPU0_SA_DQ<31>")
	)
	(arc
		(start 342.116664 -263.197086)
		(mid 341.83749 -263.121321)
		(end 341.557356 -263.19353)
		(width 0.088646)
		(layer "In6.Cu")
		(net "M_C_CPU0_SA_DQ<31>")
	)
	(arc
		(start 343.996264 -263.197086)
		(mid 343.71709 -263.121321)
		(end 343.436956 -263.19353)
		(width 0.088646)
		(layer "In6.Cu")
		(net "M_C_CPU0_SA_DQ<31>")
	)
	(arc
		(start 344.274902 -263.620758)
		(mid 344.185744 -263.37594)
		(end 343.996264 -263.197086)
		(width 0.088646)
		(layer "In6.Cu")
		(net "M_C_CPU0_SA_DQ<31>")
	)
	(arc
		(start 333.658464 -263.196832)
		(mid 333.375762 -263.12109)
		(end 333.09306 -263.196832)
		(width 0.088646)
		(layer "In6.Cu")
		(net "M_C_CPU0_SA_DQ<31>")
	)
	(arc
		(start 342.485472 -263.200388)
		(mid 342.300617 -263.247306)
		(end 342.116664 -263.197086)
		(width 0.088646)
		(layer "In6.Cu")
		(net "M_C_CPU0_SA_DQ<31>")
	)
	(segment
		(start 282.811982 -281.466798)
		(end 281.497278 -281.466798)
		(width 0.20066)
		(layer "F.Cu")
		(net "M_C_CPU0_SA_DQ<30>")
	)
	(segment
		(start 276.415246 -281.466798)
		(end 275.268182 -281.466798)
		(width 0.20066)
		(layer "F.Cu")
		(net "M_C_CPU0_SA_DQ<30>")
	)
	(segment
		(start 280.689558 -281.511248)
		(end 280.689558 -281.18562)
		(width 0.20066)
		(layer "F.Cu")
		(net "M_C_CPU0_SA_DQ<30>")
	)
	(segment
		(start 345.123262 -263.964674)
		(end 345.123262 -264.50036)
		(width 0.20066)
		(layer "F.Cu")
		(net "M_C_CPU0_SA_DQ<30>")
	)
	(segment
		(start 280.545794 -281.041856)
		(end 279.912826 -281.041856)
		(width 0.20066)
		(layer "F.Cu")
		(net "M_C_CPU0_SA_DQ<30>")
	)
	(segment
		(start 281.497278 -281.466798)
		(end 281.285442 -281.678634)
		(width 0.20066)
		(layer "F.Cu")
		(net "M_C_CPU0_SA_DQ<30>")
	)
	(segment
		(start 283.916882 -281.466798)
		(end 282.811982 -281.466798)
		(width 0.20066)
		(layer "F.Cu")
		(net "M_C_CPU0_SA_DQ<30>")
	)
	(segment
		(start 277.59787 -281.041856)
		(end 277.58771 -281.031696)
		(width 0.101854)
		(layer "F.Cu")
		(net "M_C_CPU0_SA_DQ<30>")
	)
	(segment
		(start 276.850348 -281.031696)
		(end 276.415246 -281.466798)
		(width 0.20066)
		(layer "F.Cu")
		(net "M_C_CPU0_SA_DQ<30>")
	)
	(segment
		(start 345.123516 -263.96442)
		(end 345.123262 -263.964674)
		(width 0.20066)
		(layer "F.Cu")
		(net "M_C_CPU0_SA_DQ<30>")
	)
	(segment
		(start 277.852886 -281.041856)
		(end 277.59787 -281.041856)
		(width 0.101854)
		(layer "F.Cu")
		(net "M_C_CPU0_SA_DQ<30>")
	)
	(segment
		(start 277.58771 -281.031696)
		(end 276.850348 -281.031696)
		(width 0.20066)
		(layer "F.Cu")
		(net "M_C_CPU0_SA_DQ<30>")
	)
	(segment
		(start 280.856944 -281.678634)
		(end 280.689558 -281.511248)
		(width 0.20066)
		(layer "F.Cu")
		(net "M_C_CPU0_SA_DQ<30>")
	)
	(segment
		(start 279.912826 -281.041856)
		(end 277.852886 -281.041856)
		(width 0.1016)
		(layer "F.Cu")
		(net "M_C_CPU0_SA_DQ<30>")
	)
	(segment
		(start 281.285442 -281.678634)
		(end 280.856944 -281.678634)
		(width 0.20066)
		(layer "F.Cu")
		(net "M_C_CPU0_SA_DQ<30>")
	)
	(segment
		(start 280.689558 -281.18562)
		(end 280.545794 -281.041856)
		(width 0.20066)
		(layer "F.Cu")
		(net "M_C_CPU0_SA_DQ<30>")
	)
	(segment
		(start 300.91888 -275.850604)
		(end 301.111666 -276.04339)
		(width 0.18288)
		(layer "In6.Cu")
		(net "M_C_CPU0_SA_DQ<30>")
	)
	(segment
		(start 342.031828 -264.004806)
		(end 342.021414 -264.010902)
		(width 0.088646)
		(layer "In6.Cu")
		(net "M_C_CPU0_SA_DQ<30>")
	)
	(segment
		(start 311.916572 -273.677126)
		(end 312.147204 -273.907758)
		(width 0.18288)
		(layer "In6.Cu")
		(net "M_C_CPU0_SA_DQ<30>")
	)
	(segment
		(start 288.150046 -280.852626)
		(end 287.294828 -280.852626)
		(width 0.18288)
		(layer "In6.Cu")
		(net "M_C_CPU0_SA_DQ<30>")
	)
	(segment
		(start 286.639762 -281.739848)
		(end 286.540702 -281.978608)
		(width 0.18288)
		(layer "In6.Cu")
		(net "M_C_CPU0_SA_DQ<30>")
	)
	(segment
		(start 332.248002 -264.690606)
		(end 331.83195 -265.106658)
		(width 0.088646)
		(layer "In6.Cu")
		(net "M_C_CPU0_SA_DQ<30>")
	)
	(segment
		(start 343.537286 -264.017252)
		(end 343.511632 -264.002266)
		(width 0.088646)
		(layer "In6.Cu")
		(net "M_C_CPU0_SA_DQ<30>")
	)
	(segment
		(start 345.123262 -264.50036)
		(end 344.56497 -264.068814)
		(width 0.088646)
		(layer "In6.Cu")
		(net "M_C_CPU0_SA_DQ<30>")
	)
	(segment
		(start 301.111666 -276.04339)
		(end 301.111666 -276.301962)
		(width 0.18288)
		(layer "In6.Cu")
		(net "M_C_CPU0_SA_DQ<30>")
	)
	(segment
		(start 286.91967 -281.227784)
		(end 286.668464 -281.331924)
		(width 0.18288)
		(layer "In6.Cu")
		(net "M_C_CPU0_SA_DQ<30>")
	)
	(segment
		(start 295.33215 -277.641558)
		(end 294.19931 -277.641558)
		(width 0.18288)
		(layer "In6.Cu")
		(net "M_C_CPU0_SA_DQ<30>")
	)
	(segment
		(start 312.405268 -273.18843)
		(end 312.146696 -273.18843)
		(width 0.18288)
		(layer "In6.Cu")
		(net "M_C_CPU0_SA_DQ<30>")
	)
	(segment
		(start 326.878188 -267.060426)
		(end 321.847972 -267.060426)
		(width 0.18288)
		(layer "In6.Cu")
		(net "M_C_CPU0_SA_DQ<30>")
	)
	(segment
		(start 293.324026 -278.516842)
		(end 292.501066 -278.516842)
		(width 0.18288)
		(layer "In6.Cu")
		(net "M_C_CPU0_SA_DQ<30>")
	)
	(segment
		(start 292.501066 -278.516842)
		(end 291.486082 -279.531826)
		(width 0.18288)
		(layer "In6.Cu")
		(net "M_C_CPU0_SA_DQ<30>")
	)
	(segment
		(start 302.661574 -275.301202)
		(end 302.112426 -275.301202)
		(width 0.18288)
		(layer "In6.Cu")
		(net "M_C_CPU0_SA_DQ<30>")
	)
	(segment
		(start 301.858934 -275.554694)
		(end 301.600362 -275.554694)
		(width 0.18288)
		(layer "In6.Cu")
		(net "M_C_CPU0_SA_DQ<30>")
	)
	(segment
		(start 338.272374 -264.004806)
		(end 338.26196 -264.010902)
		(width 0.088646)
		(layer "In6.Cu")
		(net "M_C_CPU0_SA_DQ<30>")
	)
	(segment
		(start 291.017452 -279.531826)
		(end 290.41344 -280.135838)
		(width 0.18288)
		(layer "In6.Cu")
		(net "M_C_CPU0_SA_DQ<30>")
	)
	(segment
		(start 308.924198 -273.945858)
		(end 308.741318 -273.762978)
		(width 0.18288)
		(layer "In6.Cu")
		(net "M_C_CPU0_SA_DQ<30>")
	)
	(segment
		(start 294.19931 -277.641558)
		(end 293.324026 -278.516842)
		(width 0.18288)
		(layer "In6.Cu")
		(net "M_C_CPU0_SA_DQ<30>")
	)
	(segment
		(start 286.540702 -281.978608)
		(end 286.24022 -282.103322)
		(width 0.18288)
		(layer "In6.Cu")
		(net "M_C_CPU0_SA_DQ<30>")
	)
	(segment
		(start 341.096346 -264.002266)
		(end 341.081614 -264.010902)
		(width 0.088646)
		(layer "In6.Cu")
		(net "M_C_CPU0_SA_DQ<30>")
	)
	(segment
		(start 308.050438 -274.443444)
		(end 303.519332 -274.443444)
		(width 0.18288)
		(layer "In6.Cu")
		(net "M_C_CPU0_SA_DQ<30>")
	)
	(segment
		(start 312.894472 -273.419062)
		(end 312.6359 -273.419062)
		(width 0.18288)
		(layer "In6.Cu")
		(net "M_C_CPU0_SA_DQ<30>")
	)
	(segment
		(start 297.951398 -276.79142)
		(end 297.10126 -277.641558)
		(width 0.18288)
		(layer "In6.Cu")
		(net "M_C_CPU0_SA_DQ<30>")
	)
	(segment
		(start 314.421774 -272.503646)
		(end 313.809888 -272.503646)
		(width 0.18288)
		(layer "In6.Cu")
		(net "M_C_CPU0_SA_DQ<30>")
	)
	(segment
		(start 296.375328 -277.641558)
		(end 296.02303 -277.993856)
		(width 0.18288)
		(layer "In6.Cu")
		(net "M_C_CPU0_SA_DQ<30>")
	)
	(segment
		(start 288.866834 -280.135838)
		(end 288.150046 -280.852626)
		(width 0.18288)
		(layer "In6.Cu")
		(net "M_C_CPU0_SA_DQ<30>")
	)
	(segment
		(start 308.416198 -273.762978)
		(end 308.233318 -273.945858)
		(width 0.18288)
		(layer "In6.Cu")
		(net "M_C_CPU0_SA_DQ<30>")
	)
	(segment
		(start 329.891898 -265.81227)
		(end 326.878188 -267.060426)
		(width 0.18288)
		(layer "In6.Cu")
		(net "M_C_CPU0_SA_DQ<30>")
	)
	(segment
		(start 344.56497 -264.068814)
		(end 344.481912 -264.020046)
		(width 0.088646)
		(layer "In6.Cu")
		(net "M_C_CPU0_SA_DQ<30>")
	)
	(segment
		(start 301.111666 -276.301962)
		(end 300.622208 -276.79142)
		(width 0.18288)
		(layer "In6.Cu")
		(net "M_C_CPU0_SA_DQ<30>")
	)
	(segment
		(start 312.147204 -273.907758)
		(end 312.147204 -274.16633)
		(width 0.18288)
		(layer "In6.Cu")
		(net "M_C_CPU0_SA_DQ<30>")
	)
	(segment
		(start 284.98927 -282.027376)
		(end 284.47746 -282.027376)
		(width 0.18288)
		(layer "In6.Cu")
		(net "M_C_CPU0_SA_DQ<30>")
	)
	(segment
		(start 311.87009 -274.443444)
		(end 309.107078 -274.443444)
		(width 0.18288)
		(layer "In6.Cu")
		(net "M_C_CPU0_SA_DQ<30>")
	)
	(segment
		(start 321.847972 -267.060426)
		(end 318.46266 -268.46276)
		(width 0.18288)
		(layer "In6.Cu")
		(net "M_C_CPU0_SA_DQ<30>")
	)
	(segment
		(start 300.622208 -276.79142)
		(end 297.951398 -276.79142)
		(width 0.18288)
		(layer "In6.Cu")
		(net "M_C_CPU0_SA_DQ<30>")
	)
	(segment
		(start 296.02303 -277.993856)
		(end 295.684448 -277.993856)
		(width 0.18288)
		(layer "In6.Cu")
		(net "M_C_CPU0_SA_DQ<30>")
	)
	(segment
		(start 303.519332 -274.443444)
		(end 302.661574 -275.301202)
		(width 0.18288)
		(layer "In6.Cu")
		(net "M_C_CPU0_SA_DQ<30>")
	)
	(segment
		(start 332.248002 -264.358628)
		(end 332.248002 -264.690606)
		(width 0.088646)
		(layer "In6.Cu")
		(net "M_C_CPU0_SA_DQ<30>")
	)
	(segment
		(start 286.24022 -282.103322)
		(end 286.00146 -282.004262)
		(width 0.18288)
		(layer "In6.Cu")
		(net "M_C_CPU0_SA_DQ<30>")
	)
	(segment
		(start 301.407576 -275.361908)
		(end 301.149004 -275.361908)
		(width 0.18288)
		(layer "In6.Cu")
		(net "M_C_CPU0_SA_DQ<30>")
	)
	(segment
		(start 311.916572 -273.418554)
		(end 311.916572 -273.677126)
		(width 0.18288)
		(layer "In6.Cu")
		(net "M_C_CPU0_SA_DQ<30>")
	)
	(segment
		(start 285.692342 -281.736038)
		(end 284.98927 -282.027376)
		(width 0.18288)
		(layer "In6.Cu")
		(net "M_C_CPU0_SA_DQ<30>")
	)
	(segment
		(start 301.600362 -275.554694)
		(end 301.407576 -275.361908)
		(width 0.18288)
		(layer "In6.Cu")
		(net "M_C_CPU0_SA_DQ<30>")
	)
	(segment
		(start 287.294828 -280.852626)
		(end 286.91967 -281.227784)
		(width 0.18288)
		(layer "In6.Cu")
		(net "M_C_CPU0_SA_DQ<30>")
	)
	(segment
		(start 340.156546 -264.002266)
		(end 340.141814 -264.010902)
		(width 0.088646)
		(layer "In6.Cu")
		(net "M_C_CPU0_SA_DQ<30>")
	)
	(segment
		(start 300.91888 -275.592032)
		(end 300.91888 -275.850604)
		(width 0.18288)
		(layer "In6.Cu")
		(net "M_C_CPU0_SA_DQ<30>")
	)
	(segment
		(start 308.741318 -273.762978)
		(end 308.416198 -273.762978)
		(width 0.18288)
		(layer "In6.Cu")
		(net "M_C_CPU0_SA_DQ<30>")
	)
	(segment
		(start 308.233318 -274.260564)
		(end 308.050438 -274.443444)
		(width 0.18288)
		(layer "In6.Cu")
		(net "M_C_CPU0_SA_DQ<30>")
	)
	(segment
		(start 286.00146 -282.004262)
		(end 285.931102 -281.835098)
		(width 0.18288)
		(layer "In6.Cu")
		(net "M_C_CPU0_SA_DQ<30>")
	)
	(segment
		(start 286.569404 -281.57043)
		(end 286.639762 -281.739848)
		(width 0.18288)
		(layer "In6.Cu")
		(net "M_C_CPU0_SA_DQ<30>")
	)
	(segment
		(start 313.809888 -272.503646)
		(end 312.894472 -273.419062)
		(width 0.18288)
		(layer "In6.Cu")
		(net "M_C_CPU0_SA_DQ<30>")
	)
	(segment
		(start 290.41344 -280.135838)
		(end 288.866834 -280.135838)
		(width 0.18288)
		(layer "In6.Cu")
		(net "M_C_CPU0_SA_DQ<30>")
	)
	(segment
		(start 332.506066 -264.100564)
		(end 332.248002 -264.358628)
		(width 0.088646)
		(layer "In6.Cu")
		(net "M_C_CPU0_SA_DQ<30>")
	)
	(segment
		(start 308.924198 -274.260564)
		(end 308.924198 -273.945858)
		(width 0.18288)
		(layer "In6.Cu")
		(net "M_C_CPU0_SA_DQ<30>")
	)
	(segment
		(start 286.668464 -281.331924)
		(end 286.569404 -281.57043)
		(width 0.18288)
		(layer "In6.Cu")
		(net "M_C_CPU0_SA_DQ<30>")
	)
	(segment
		(start 318.46266 -268.46276)
		(end 314.421774 -272.503646)
		(width 0.18288)
		(layer "In6.Cu")
		(net "M_C_CPU0_SA_DQ<30>")
	)
	(segment
		(start 301.149004 -275.361908)
		(end 300.91888 -275.592032)
		(width 0.18288)
		(layer "In6.Cu")
		(net "M_C_CPU0_SA_DQ<30>")
	)
	(segment
		(start 312.6359 -273.419062)
		(end 312.405268 -273.18843)
		(width 0.18288)
		(layer "In6.Cu")
		(net "M_C_CPU0_SA_DQ<30>")
	)
	(segment
		(start 295.684448 -277.993856)
		(end 295.33215 -277.641558)
		(width 0.18288)
		(layer "In6.Cu")
		(net "M_C_CPU0_SA_DQ<30>")
	)
	(segment
		(start 297.10126 -277.641558)
		(end 296.375328 -277.641558)
		(width 0.18288)
		(layer "In6.Cu")
		(net "M_C_CPU0_SA_DQ<30>")
	)
	(segment
		(start 302.112426 -275.301202)
		(end 301.858934 -275.554694)
		(width 0.18288)
		(layer "In6.Cu")
		(net "M_C_CPU0_SA_DQ<30>")
	)
	(segment
		(start 312.147204 -274.16633)
		(end 311.87009 -274.443444)
		(width 0.18288)
		(layer "In6.Cu")
		(net "M_C_CPU0_SA_DQ<30>")
	)
	(segment
		(start 331.83195 -265.106658)
		(end 331.83195 -265.510264)
		(width 0.088646)
		(layer "In6.Cu")
		(net "M_C_CPU0_SA_DQ<30>")
	)
	(segment
		(start 291.486082 -279.531826)
		(end 291.017452 -279.531826)
		(width 0.18288)
		(layer "In6.Cu")
		(net "M_C_CPU0_SA_DQ<30>")
	)
	(segment
		(start 284.47746 -282.027376)
		(end 283.916882 -281.466798)
		(width 0.18288)
		(layer "In6.Cu")
		(net "M_C_CPU0_SA_DQ<30>")
	)
	(segment
		(start 312.146696 -273.18843)
		(end 311.916572 -273.418554)
		(width 0.18288)
		(layer "In6.Cu")
		(net "M_C_CPU0_SA_DQ<30>")
	)
	(segment
		(start 331.83195 -265.510264)
		(end 331.529944 -265.81227)
		(width 0.088646)
		(layer "In6.Cu")
		(net "M_C_CPU0_SA_DQ<30>")
	)
	(segment
		(start 285.931102 -281.835098)
		(end 285.692342 -281.736038)
		(width 0.18288)
		(layer "In6.Cu")
		(net "M_C_CPU0_SA_DQ<30>")
	)
	(segment
		(start 331.529944 -265.81227)
		(end 330.979272 -265.81227)
		(width 0.088646)
		(layer "In6.Cu")
		(net "M_C_CPU0_SA_DQ<30>")
	)
	(segment
		(start 309.107078 -274.443444)
		(end 308.924198 -274.260564)
		(width 0.18288)
		(layer "In6.Cu")
		(net "M_C_CPU0_SA_DQ<30>")
	)
	(segment
		(start 308.233318 -273.945858)
		(end 308.233318 -274.260564)
		(width 0.18288)
		(layer "In6.Cu")
		(net "M_C_CPU0_SA_DQ<30>")
	)
	(segment
		(start 330.979272 -265.81227)
		(end 329.891898 -265.81227)
		(width 0.18288)
		(layer "In6.Cu")
		(net "M_C_CPU0_SA_DQ<30>")
	)
	(arc
		(start 342.96096 -264.010902)
		(mid 342.773762 -264.061045)
		(end 342.586564 -264.010902)
		(width 0.088646)
		(layer "In6.Cu")
		(net "M_C_CPU0_SA_DQ<30>")
	)
	(arc
		(start 341.647018 -264.010902)
		(mid 341.372819 -263.935067)
		(end 341.096346 -264.002266)
		(width 0.088646)
		(layer "In6.Cu")
		(net "M_C_CPU0_SA_DQ<30>")
	)
	(arc
		(start 335.44256 -264.010902)
		(mid 335.255362 -264.061045)
		(end 335.068164 -264.010902)
		(width 0.088646)
		(layer "In6.Cu")
		(net "M_C_CPU0_SA_DQ<30>")
	)
	(arc
		(start 341.081614 -264.010902)
		(mid 340.894416 -264.061045)
		(end 340.707218 -264.010902)
		(width 0.088646)
		(layer "In6.Cu")
		(net "M_C_CPU0_SA_DQ<30>")
	)
	(arc
		(start 335.068164 -264.010902)
		(mid 334.785462 -263.935126)
		(end 334.50276 -264.010902)
		(width 0.088646)
		(layer "In6.Cu")
		(net "M_C_CPU0_SA_DQ<30>")
	)
	(arc
		(start 333.188564 -264.010902)
		(mid 332.905862 -263.935126)
		(end 332.62316 -264.010902)
		(width 0.088646)
		(layer "In6.Cu")
		(net "M_C_CPU0_SA_DQ<30>")
	)
	(arc
		(start 332.62316 -264.010902)
		(mid 332.561682 -264.051904)
		(end 332.506066 -264.100564)
		(width 0.088646)
		(layer "In6.Cu")
		(net "M_C_CPU0_SA_DQ<30>")
	)
	(arc
		(start 339.202014 -264.010902)
		(mid 339.014816 -264.061045)
		(end 338.827618 -264.010902)
		(width 0.088646)
		(layer "In6.Cu")
		(net "M_C_CPU0_SA_DQ<30>")
	)
	(arc
		(start 334.50276 -264.010902)
		(mid 334.315562 -264.061045)
		(end 334.128364 -264.010902)
		(width 0.088646)
		(layer "In6.Cu")
		(net "M_C_CPU0_SA_DQ<30>")
	)
	(arc
		(start 337.32216 -264.010902)
		(mid 337.134962 -264.061045)
		(end 336.947764 -264.010902)
		(width 0.088646)
		(layer "In6.Cu")
		(net "M_C_CPU0_SA_DQ<30>")
	)
	(arc
		(start 344.481912 -264.020046)
		(mid 344.197643 -263.942533)
		(end 343.912952 -264.018522)
		(width 0.088646)
		(layer "In6.Cu")
		(net "M_C_CPU0_SA_DQ<30>")
	)
	(arc
		(start 338.26196 -264.010902)
		(mid 338.074762 -264.061045)
		(end 337.887564 -264.010902)
		(width 0.088646)
		(layer "In6.Cu")
		(net "M_C_CPU0_SA_DQ<30>")
	)
	(arc
		(start 343.912952 -264.018522)
		(mid 343.724955 -264.068511)
		(end 343.537286 -264.017252)
		(width 0.088646)
		(layer "In6.Cu")
		(net "M_C_CPU0_SA_DQ<30>")
	)
	(arc
		(start 342.021414 -264.010902)
		(mid 341.834216 -264.061045)
		(end 341.647018 -264.010902)
		(width 0.088646)
		(layer "In6.Cu")
		(net "M_C_CPU0_SA_DQ<30>")
	)
	(arc
		(start 340.141814 -264.010902)
		(mid 339.954616 -264.061045)
		(end 339.767418 -264.010902)
		(width 0.088646)
		(layer "In6.Cu")
		(net "M_C_CPU0_SA_DQ<30>")
	)
	(arc
		(start 342.586564 -264.010902)
		(mid 342.310005 -263.935159)
		(end 342.031828 -264.004806)
		(width 0.088646)
		(layer "In6.Cu")
		(net "M_C_CPU0_SA_DQ<30>")
	)
	(arc
		(start 336.38236 -264.010902)
		(mid 336.195162 -264.061045)
		(end 336.007964 -264.010902)
		(width 0.088646)
		(layer "In6.Cu")
		(net "M_C_CPU0_SA_DQ<30>")
	)
	(arc
		(start 336.007964 -264.010902)
		(mid 335.725262 -263.935126)
		(end 335.44256 -264.010902)
		(width 0.088646)
		(layer "In6.Cu")
		(net "M_C_CPU0_SA_DQ<30>")
	)
	(arc
		(start 343.511632 -264.002266)
		(mid 343.235157 -263.934946)
		(end 342.96096 -264.010902)
		(width 0.088646)
		(layer "In6.Cu")
		(net "M_C_CPU0_SA_DQ<30>")
	)
	(arc
		(start 339.767418 -264.010902)
		(mid 339.484716 -263.935126)
		(end 339.202014 -264.010902)
		(width 0.088646)
		(layer "In6.Cu")
		(net "M_C_CPU0_SA_DQ<30>")
	)
	(arc
		(start 333.56296 -264.010902)
		(mid 333.375762 -264.061045)
		(end 333.188564 -264.010902)
		(width 0.088646)
		(layer "In6.Cu")
		(net "M_C_CPU0_SA_DQ<30>")
	)
	(arc
		(start 337.887564 -264.010902)
		(mid 337.604862 -263.935126)
		(end 337.32216 -264.010902)
		(width 0.088646)
		(layer "In6.Cu")
		(net "M_C_CPU0_SA_DQ<30>")
	)
	(arc
		(start 340.707218 -264.010902)
		(mid 340.433019 -263.935067)
		(end 340.156546 -264.002266)
		(width 0.088646)
		(layer "In6.Cu")
		(net "M_C_CPU0_SA_DQ<30>")
	)
	(arc
		(start 336.947764 -264.010902)
		(mid 336.665062 -263.935126)
		(end 336.38236 -264.010902)
		(width 0.088646)
		(layer "In6.Cu")
		(net "M_C_CPU0_SA_DQ<30>")
	)
	(arc
		(start 334.128364 -264.010902)
		(mid 333.845662 -263.935126)
		(end 333.56296 -264.010902)
		(width 0.088646)
		(layer "In6.Cu")
		(net "M_C_CPU0_SA_DQ<30>")
	)
	(arc
		(start 338.827618 -264.010902)
		(mid 338.550805 -263.935032)
		(end 338.272374 -264.004806)
		(width 0.088646)
		(layer "In6.Cu")
		(net "M_C_CPU0_SA_DQ<30>")
	)
	(segment
		(start 341.364316 -278.614378)
		(end 341.364062 -279.150318)
		(width 0.20066)
		(layer "F.Cu")
		(net "M_C_CPU0_SA_DQ<2>")
	)
	(segment
		(start 280.689558 -315.51118)
		(end 280.689558 -315.185552)
		(width 0.20066)
		(layer "F.Cu")
		(net "M_C_CPU0_SA_DQ<2>")
	)
	(segment
		(start 277.59787 -315.041788)
		(end 277.58771 -315.031628)
		(width 0.101854)
		(layer "F.Cu")
		(net "M_C_CPU0_SA_DQ<2>")
	)
	(segment
		(start 280.856944 -315.678566)
		(end 280.689558 -315.51118)
		(width 0.20066)
		(layer "F.Cu")
		(net "M_C_CPU0_SA_DQ<2>")
	)
	(segment
		(start 280.545794 -315.041788)
		(end 279.912826 -315.041788)
		(width 0.20066)
		(layer "F.Cu")
		(net "M_C_CPU0_SA_DQ<2>")
	)
	(segment
		(start 277.58771 -315.031628)
		(end 276.850348 -315.031628)
		(width 0.20066)
		(layer "F.Cu")
		(net "M_C_CPU0_SA_DQ<2>")
	)
	(segment
		(start 281.497278 -315.46673)
		(end 281.285442 -315.678566)
		(width 0.20066)
		(layer "F.Cu")
		(net "M_C_CPU0_SA_DQ<2>")
	)
	(segment
		(start 283.916882 -315.46673)
		(end 282.811982 -315.46673)
		(width 0.20066)
		(layer "F.Cu")
		(net "M_C_CPU0_SA_DQ<2>")
	)
	(segment
		(start 276.850348 -315.031628)
		(end 276.415246 -315.46673)
		(width 0.20066)
		(layer "F.Cu")
		(net "M_C_CPU0_SA_DQ<2>")
	)
	(segment
		(start 280.689558 -315.185552)
		(end 280.545794 -315.041788)
		(width 0.20066)
		(layer "F.Cu")
		(net "M_C_CPU0_SA_DQ<2>")
	)
	(segment
		(start 281.285442 -315.678566)
		(end 280.856944 -315.678566)
		(width 0.20066)
		(layer "F.Cu")
		(net "M_C_CPU0_SA_DQ<2>")
	)
	(segment
		(start 276.415246 -315.46673)
		(end 275.268182 -315.46673)
		(width 0.20066)
		(layer "F.Cu")
		(net "M_C_CPU0_SA_DQ<2>")
	)
	(segment
		(start 277.852886 -315.041788)
		(end 277.59787 -315.041788)
		(width 0.101854)
		(layer "F.Cu")
		(net "M_C_CPU0_SA_DQ<2>")
	)
	(segment
		(start 282.811982 -315.46673)
		(end 281.497278 -315.46673)
		(width 0.20066)
		(layer "F.Cu")
		(net "M_C_CPU0_SA_DQ<2>")
	)
	(segment
		(start 279.912826 -315.041788)
		(end 277.852886 -315.041788)
		(width 0.1016)
		(layer "F.Cu")
		(net "M_C_CPU0_SA_DQ<2>")
	)
	(segment
		(start 338.919312 -284.023816)
		(end 338.919312 -284.033722)
		(width 0.088646)
		(layer "In4.Cu")
		(net "M_C_CPU0_SA_DQ<2>")
	)
	(segment
		(start 331.665326 -289.796474)
		(end 328.104754 -298.39031)
		(width 0.18288)
		(layer "In4.Cu")
		(net "M_C_CPU0_SA_DQ<2>")
	)
	(segment
		(start 286.069786 -317.30442)
		(end 285.886906 -317.12154)
		(width 0.18288)
		(layer "In4.Cu")
		(net "M_C_CPU0_SA_DQ<2>")
	)
	(segment
		(start 337.509612 -284.837632)
		(end 337.509612 -284.847538)
		(width 0.088646)
		(layer "In4.Cu")
		(net "M_C_CPU0_SA_DQ<2>")
	)
	(segment
		(start 333.586836 -287.874964)
		(end 331.665326 -289.796474)
		(width 0.18288)
		(layer "In4.Cu")
		(net "M_C_CPU0_SA_DQ<2>")
	)
	(segment
		(start 339.859366 -282.390342)
		(end 339.859366 -282.405836)
		(width 0.088646)
		(layer "In4.Cu")
		(net "M_C_CPU0_SA_DQ<2>")
	)
	(segment
		(start 293.40556 -318.441578)
		(end 291.327332 -317.580772)
		(width 0.18288)
		(layer "In4.Cu")
		(net "M_C_CPU0_SA_DQ<2>")
	)
	(segment
		(start 303.758346 -316.924436)
		(end 303.024794 -317.657988)
		(width 0.18288)
		(layer "In4.Cu")
		(net "M_C_CPU0_SA_DQ<2>")
	)
	(segment
		(start 288.891472 -317.580772)
		(end 287.310068 -315.999368)
		(width 0.18288)
		(layer "In4.Cu")
		(net "M_C_CPU0_SA_DQ<2>")
	)
	(segment
		(start 340.150704 -280.283412)
		(end 340.141814 -280.288492)
		(width 0.088646)
		(layer "In4.Cu")
		(net "M_C_CPU0_SA_DQ<2>")
	)
	(segment
		(start 308.768496 -316.625224)
		(end 307.58638 -316.625224)
		(width 0.18288)
		(layer "In4.Cu")
		(net "M_C_CPU0_SA_DQ<2>")
	)
	(segment
		(start 304.687732 -316.924436)
		(end 303.758346 -316.924436)
		(width 0.18288)
		(layer "In4.Cu")
		(net "M_C_CPU0_SA_DQ<2>")
	)
	(segment
		(start 340.15045 -281.911298)
		(end 340.14156 -281.916378)
		(width 0.088646)
		(layer "In4.Cu")
		(net "M_C_CPU0_SA_DQ<2>")
	)
	(segment
		(start 307.58638 -316.625224)
		(end 306.699412 -315.738256)
		(width 0.18288)
		(layer "In4.Cu")
		(net "M_C_CPU0_SA_DQ<2>")
	)
	(segment
		(start 300.543722 -318.441578)
		(end 293.40556 -318.441578)
		(width 0.18288)
		(layer "In4.Cu")
		(net "M_C_CPU0_SA_DQ<2>")
	)
	(segment
		(start 286.587946 -317.1444)
		(end 286.427926 -317.30442)
		(width 0.18288)
		(layer "In4.Cu")
		(net "M_C_CPU0_SA_DQ<2>")
	)
	(segment
		(start 340.14156 -281.267662)
		(end 340.15045 -281.272742)
		(width 0.088646)
		(layer "In4.Cu")
		(net "M_C_CPU0_SA_DQ<2>")
	)
	(segment
		(start 336.39125 -286.794702)
		(end 336.38236 -286.799782)
		(width 0.088646)
		(layer "In4.Cu")
		(net "M_C_CPU0_SA_DQ<2>")
	)
	(segment
		(start 310.93664 -315.32068)
		(end 310.174894 -316.082426)
		(width 0.18288)
		(layer "In4.Cu")
		(net "M_C_CPU0_SA_DQ<2>")
	)
	(segment
		(start 340.184486 -279.554432)
		(end 340.189312 -279.557226)
		(width 0.088646)
		(layer "In4.Cu")
		(net "M_C_CPU0_SA_DQ<2>")
	)
	(segment
		(start 301.327312 -317.657988)
		(end 300.543722 -318.441578)
		(width 0.18288)
		(layer "In4.Cu")
		(net "M_C_CPU0_SA_DQ<2>")
	)
	(segment
		(start 339.859366 -280.759662)
		(end 339.859366 -280.793698)
		(width 0.088646)
		(layer "In4.Cu")
		(net "M_C_CPU0_SA_DQ<2>")
	)
	(segment
		(start 338.74075 -284.353)
		(end 338.73186 -284.35808)
		(width 0.088646)
		(layer "In4.Cu")
		(net "M_C_CPU0_SA_DQ<2>")
	)
	(segment
		(start 335.92135 -287.608518)
		(end 335.91246 -287.613598)
		(width 0.088646)
		(layer "In4.Cu")
		(net "M_C_CPU0_SA_DQ<2>")
	)
	(segment
		(start 339.680804 -282.725114)
		(end 339.671914 -282.730194)
		(width 0.088646)
		(layer "In4.Cu")
		(net "M_C_CPU0_SA_DQ<2>")
	)
	(segment
		(start 285.886906 -316.159388)
		(end 285.726886 -315.999368)
		(width 0.18288)
		(layer "In4.Cu")
		(net "M_C_CPU0_SA_DQ<2>")
	)
	(segment
		(start 336.86115 -285.980632)
		(end 336.85226 -285.985712)
		(width 0.088646)
		(layer "In4.Cu")
		(net "M_C_CPU0_SA_DQ<2>")
	)
	(segment
		(start 286.816546 -315.999368)
		(end 286.587946 -316.227968)
		(width 0.18288)
		(layer "In4.Cu")
		(net "M_C_CPU0_SA_DQ<2>")
	)
	(segment
		(start 334.855566 -287.70326)
		(end 334.683862 -287.874964)
		(width 0.088646)
		(layer "In4.Cu")
		(net "M_C_CPU0_SA_DQ<2>")
	)
	(segment
		(start 341.364062 -279.150318)
		(end 340.659466 -278.74341)
		(width 0.088646)
		(layer "In4.Cu")
		(net "M_C_CPU0_SA_DQ<2>")
	)
	(segment
		(start 336.569812 -286.4612)
		(end 336.569812 -286.475424)
		(width 0.088646)
		(layer "In4.Cu")
		(net "M_C_CPU0_SA_DQ<2>")
	)
	(segment
		(start 334.683862 -287.874964)
		(end 334.129126 -287.874964)
		(width 0.088646)
		(layer "In4.Cu")
		(net "M_C_CPU0_SA_DQ<2>")
	)
	(segment
		(start 337.039712 -285.651448)
		(end 337.039712 -285.661354)
		(width 0.088646)
		(layer "In4.Cu")
		(net "M_C_CPU0_SA_DQ<2>")
	)
	(segment
		(start 286.427926 -317.30442)
		(end 286.069786 -317.30442)
		(width 0.18288)
		(layer "In4.Cu")
		(net "M_C_CPU0_SA_DQ<2>")
	)
	(segment
		(start 291.327332 -317.580772)
		(end 288.891472 -317.580772)
		(width 0.18288)
		(layer "In4.Cu")
		(net "M_C_CPU0_SA_DQ<2>")
	)
	(segment
		(start 336.099912 -287.279334)
		(end 336.099912 -287.28924)
		(width 0.088646)
		(layer "In4.Cu")
		(net "M_C_CPU0_SA_DQ<2>")
	)
	(segment
		(start 340.329266 -279.799542)
		(end 340.329266 -279.964134)
		(width 0.088646)
		(layer "In4.Cu")
		(net "M_C_CPU0_SA_DQ<2>")
	)
	(segment
		(start 321.506088 -307.378608)
		(end 314.78347 -314.101226)
		(width 0.18288)
		(layer "In4.Cu")
		(net "M_C_CPU0_SA_DQ<2>")
	)
	(segment
		(start 334.129126 -287.874964)
		(end 333.586836 -287.874964)
		(width 0.18288)
		(layer "In4.Cu")
		(net "M_C_CPU0_SA_DQ<2>")
	)
	(segment
		(start 310.174894 -316.082426)
		(end 309.311294 -316.082426)
		(width 0.18288)
		(layer "In4.Cu")
		(net "M_C_CPU0_SA_DQ<2>")
	)
	(segment
		(start 339.21065 -283.539184)
		(end 339.20176 -283.544264)
		(width 0.088646)
		(layer "In4.Cu")
		(net "M_C_CPU0_SA_DQ<2>")
	)
	(segment
		(start 286.587946 -316.227968)
		(end 286.587946 -317.1444)
		(width 0.18288)
		(layer "In4.Cu")
		(net "M_C_CPU0_SA_DQ<2>")
	)
	(segment
		(start 309.311294 -316.082426)
		(end 308.768496 -316.625224)
		(width 0.18288)
		(layer "In4.Cu")
		(net "M_C_CPU0_SA_DQ<2>")
	)
	(segment
		(start 313.768994 -314.101226)
		(end 312.54954 -315.32068)
		(width 0.18288)
		(layer "In4.Cu")
		(net "M_C_CPU0_SA_DQ<2>")
	)
	(segment
		(start 321.506088 -304.988976)
		(end 321.506088 -307.378608)
		(width 0.18288)
		(layer "In4.Cu")
		(net "M_C_CPU0_SA_DQ<2>")
	)
	(segment
		(start 285.726886 -315.999368)
		(end 284.44952 -315.999368)
		(width 0.18288)
		(layer "In4.Cu")
		(net "M_C_CPU0_SA_DQ<2>")
	)
	(segment
		(start 306.699412 -315.738256)
		(end 305.873912 -315.738256)
		(width 0.18288)
		(layer "In4.Cu")
		(net "M_C_CPU0_SA_DQ<2>")
	)
	(segment
		(start 328.104754 -298.39031)
		(end 321.506088 -304.988976)
		(width 0.18288)
		(layer "In4.Cu")
		(net "M_C_CPU0_SA_DQ<2>")
	)
	(segment
		(start 305.873912 -315.738256)
		(end 304.687732 -316.924436)
		(width 0.18288)
		(layer "In4.Cu")
		(net "M_C_CPU0_SA_DQ<2>")
	)
	(segment
		(start 337.33105 -285.166816)
		(end 337.32216 -285.171896)
		(width 0.088646)
		(layer "In4.Cu")
		(net "M_C_CPU0_SA_DQ<2>")
	)
	(segment
		(start 303.024794 -317.657988)
		(end 301.327312 -317.657988)
		(width 0.18288)
		(layer "In4.Cu")
		(net "M_C_CPU0_SA_DQ<2>")
	)
	(segment
		(start 339.389212 -283.205682)
		(end 339.389212 -283.219906)
		(width 0.088646)
		(layer "In4.Cu")
		(net "M_C_CPU0_SA_DQ<2>")
	)
	(segment
		(start 340.659466 -278.74341)
		(end 340.659212 -278.74341)
		(width 0.088646)
		(layer "In4.Cu")
		(net "M_C_CPU0_SA_DQ<2>")
	)
	(segment
		(start 284.44952 -315.999368)
		(end 283.916882 -315.46673)
		(width 0.18288)
		(layer "In4.Cu")
		(net "M_C_CPU0_SA_DQ<2>")
	)
	(segment
		(start 312.54954 -315.32068)
		(end 310.93664 -315.32068)
		(width 0.18288)
		(layer "In4.Cu")
		(net "M_C_CPU0_SA_DQ<2>")
	)
	(segment
		(start 287.310068 -315.999368)
		(end 286.816546 -315.999368)
		(width 0.18288)
		(layer "In4.Cu")
		(net "M_C_CPU0_SA_DQ<2>")
	)
	(segment
		(start 314.78347 -314.101226)
		(end 313.768994 -314.101226)
		(width 0.18288)
		(layer "In4.Cu")
		(net "M_C_CPU0_SA_DQ<2>")
	)
	(segment
		(start 285.886906 -317.12154)
		(end 285.886906 -316.159388)
		(width 0.18288)
		(layer "In4.Cu")
		(net "M_C_CPU0_SA_DQ<2>")
	)
	(arc
		(start 336.85226 -285.985712)
		(mid 336.648955 -286.186578)
		(end 336.569812 -286.4612)
		(width 0.088646)
		(layer "In4.Cu")
		(net "M_C_CPU0_SA_DQ<2>")
	)
	(arc
		(start 340.189312 -278.74341)
		(mid 340.01734 -278.915392)
		(end 339.954362 -279.150318)
		(width 0.088646)
		(layer "In4.Cu")
		(net "M_C_CPU0_SA_DQ<2>")
	)
	(arc
		(start 339.389212 -283.219906)
		(mid 339.341533 -283.402806)
		(end 339.21065 -283.539184)
		(width 0.088646)
		(layer "In4.Cu")
		(net "M_C_CPU0_SA_DQ<2>")
	)
	(arc
		(start 339.671914 -282.730194)
		(mid 339.468433 -282.930998)
		(end 339.389212 -283.205682)
		(width 0.088646)
		(layer "In4.Cu")
		(net "M_C_CPU0_SA_DQ<2>")
	)
	(arc
		(start 336.38236 -286.799782)
		(mid 336.178025 -287.002387)
		(end 336.099912 -287.279334)
		(width 0.088646)
		(layer "In4.Cu")
		(net "M_C_CPU0_SA_DQ<2>")
	)
	(arc
		(start 339.20176 -283.544264)
		(mid 338.997425 -283.746869)
		(end 338.919312 -284.023816)
		(width 0.088646)
		(layer "In4.Cu")
		(net "M_C_CPU0_SA_DQ<2>")
	)
	(arc
		(start 338.73186 -284.35808)
		(mid 338.544662 -284.408223)
		(end 338.357464 -284.35808)
		(width 0.088646)
		(layer "In4.Cu")
		(net "M_C_CPU0_SA_DQ<2>")
	)
	(arc
		(start 337.039712 -285.661354)
		(mid 336.992033 -285.844254)
		(end 336.86115 -285.980632)
		(width 0.088646)
		(layer "In4.Cu")
		(net "M_C_CPU0_SA_DQ<2>")
	)
	(arc
		(start 339.954362 -279.150318)
		(mid 340.015925 -279.382841)
		(end 340.184486 -279.554432)
		(width 0.088646)
		(layer "In4.Cu")
		(net "M_C_CPU0_SA_DQ<2>")
	)
	(arc
		(start 335.538064 -287.613598)
		(mid 335.255362 -287.537822)
		(end 334.97266 -287.613598)
		(width 0.088646)
		(layer "In4.Cu")
		(net "M_C_CPU0_SA_DQ<2>")
	)
	(arc
		(start 339.859366 -282.405836)
		(mid 339.811687 -282.588736)
		(end 339.680804 -282.725114)
		(width 0.088646)
		(layer "In4.Cu")
		(net "M_C_CPU0_SA_DQ<2>")
	)
	(arc
		(start 335.91246 -287.613598)
		(mid 335.725262 -287.663741)
		(end 335.538064 -287.613598)
		(width 0.088646)
		(layer "In4.Cu")
		(net "M_C_CPU0_SA_DQ<2>")
	)
	(arc
		(start 337.79206 -284.35808)
		(mid 337.587725 -284.560685)
		(end 337.509612 -284.837632)
		(width 0.088646)
		(layer "In4.Cu")
		(net "M_C_CPU0_SA_DQ<2>")
	)
	(arc
		(start 334.97266 -287.613598)
		(mid 334.911182 -287.6546)
		(end 334.855566 -287.70326)
		(width 0.088646)
		(layer "In4.Cu")
		(net "M_C_CPU0_SA_DQ<2>")
	)
	(arc
		(start 340.189312 -279.557226)
		(mid 340.291797 -279.659616)
		(end 340.329266 -279.799542)
		(width 0.088646)
		(layer "In4.Cu")
		(net "M_C_CPU0_SA_DQ<2>")
	)
	(arc
		(start 338.919312 -284.033722)
		(mid 338.871633 -284.216622)
		(end 338.74075 -284.353)
		(width 0.088646)
		(layer "In4.Cu")
		(net "M_C_CPU0_SA_DQ<2>")
	)
	(arc
		(start 338.357464 -284.35808)
		(mid 338.074762 -284.282304)
		(end 337.79206 -284.35808)
		(width 0.088646)
		(layer "In4.Cu")
		(net "M_C_CPU0_SA_DQ<2>")
	)
	(arc
		(start 340.14156 -281.916378)
		(mid 339.938737 -282.116609)
		(end 339.859366 -282.390342)
		(width 0.088646)
		(layer "In4.Cu")
		(net "M_C_CPU0_SA_DQ<2>")
	)
	(arc
		(start 340.15045 -281.272742)
		(mid 340.329047 -281.59202)
		(end 340.15045 -281.911298)
		(width 0.088646)
		(layer "In4.Cu")
		(net "M_C_CPU0_SA_DQ<2>")
	)
	(arc
		(start 336.099912 -287.28924)
		(mid 336.052233 -287.47214)
		(end 335.92135 -287.608518)
		(width 0.088646)
		(layer "In4.Cu")
		(net "M_C_CPU0_SA_DQ<2>")
	)
	(arc
		(start 340.141814 -280.288492)
		(mid 339.939528 -280.487473)
		(end 339.859366 -280.759662)
		(width 0.088646)
		(layer "In4.Cu")
		(net "M_C_CPU0_SA_DQ<2>")
	)
	(arc
		(start 337.32216 -285.171896)
		(mid 337.117825 -285.374501)
		(end 337.039712 -285.651448)
		(width 0.088646)
		(layer "In4.Cu")
		(net "M_C_CPU0_SA_DQ<2>")
	)
	(arc
		(start 337.509612 -284.847538)
		(mid 337.461933 -285.030438)
		(end 337.33105 -285.166816)
		(width 0.088646)
		(layer "In4.Cu")
		(net "M_C_CPU0_SA_DQ<2>")
	)
	(arc
		(start 340.329266 -279.964134)
		(mid 340.281587 -280.147034)
		(end 340.150704 -280.283412)
		(width 0.088646)
		(layer "In4.Cu")
		(net "M_C_CPU0_SA_DQ<2>")
	)
	(arc
		(start 340.659212 -278.74341)
		(mid 340.424262 -278.68045)
		(end 340.189312 -278.74341)
		(width 0.088646)
		(layer "In4.Cu")
		(net "M_C_CPU0_SA_DQ<2>")
	)
	(arc
		(start 336.569812 -286.475424)
		(mid 336.522133 -286.658324)
		(end 336.39125 -286.794702)
		(width 0.088646)
		(layer "In4.Cu")
		(net "M_C_CPU0_SA_DQ<2>")
	)
	(arc
		(start 339.859366 -280.793698)
		(mid 339.938736 -281.067432)
		(end 340.14156 -281.267662)
		(width 0.088646)
		(layer "In4.Cu")
		(net "M_C_CPU0_SA_DQ<2>")
	)
	(segment
		(start 343.713562 -263.150604)
		(end 343.713562 -263.68629)
		(width 0.20066)
		(layer "F.Cu")
		(net "M_C_CPU0_SA_DQ<29>")
	)
	(segment
		(start 276.647656 -280.191718)
		(end 276.469094 -280.191718)
		(width 0.20066)
		(layer "F.Cu")
		(net "M_C_CPU0_SA_DQ<29>")
	)
	(segment
		(start 273.37258 -280.345388)
		(end 273.37258 -280.673556)
		(width 0.20066)
		(layer "F.Cu")
		(net "M_C_CPU0_SA_DQ<29>")
	)
	(segment
		(start 278.711914 -280.61666)
		(end 277.072598 -280.61666)
		(width 0.20066)
		(layer "F.Cu")
		(net "M_C_CPU0_SA_DQ<29>")
	)
	(segment
		(start 273.53514 -280.182828)
		(end 273.37258 -280.345388)
		(width 0.20066)
		(layer "F.Cu")
		(net "M_C_CPU0_SA_DQ<29>")
	)
	(segment
		(start 274.143978 -280.182828)
		(end 273.53514 -280.182828)
		(width 0.20066)
		(layer "F.Cu")
		(net "M_C_CPU0_SA_DQ<29>")
	)
	(segment
		(start 343.713562 -263.68629)
		(end 343.713816 -263.686544)
		(width 0.20066)
		(layer "F.Cu")
		(net "M_C_CPU0_SA_DQ<29>")
	)
	(segment
		(start 272.502376 -280.61666)
		(end 271.168114 -280.61666)
		(width 0.20066)
		(layer "F.Cu")
		(net "M_C_CPU0_SA_DQ<29>")
	)
	(segment
		(start 279.816814 -280.61666)
		(end 278.711914 -280.61666)
		(width 0.20066)
		(layer "F.Cu")
		(net "M_C_CPU0_SA_DQ<29>")
	)
	(segment
		(start 274.152868 -280.191718)
		(end 274.143978 -280.182828)
		(width 0.1016)
		(layer "F.Cu")
		(net "M_C_CPU0_SA_DQ<29>")
	)
	(segment
		(start 276.138386 -280.191718)
		(end 274.152868 -280.191718)
		(width 0.1016)
		(layer "F.Cu")
		(net "M_C_CPU0_SA_DQ<29>")
	)
	(segment
		(start 276.469094 -280.191718)
		(end 276.138386 -280.191718)
		(width 0.101854)
		(layer "F.Cu")
		(net "M_C_CPU0_SA_DQ<29>")
	)
	(segment
		(start 273.37258 -280.673556)
		(end 273.218148 -280.827988)
		(width 0.20066)
		(layer "F.Cu")
		(net "M_C_CPU0_SA_DQ<29>")
	)
	(segment
		(start 272.713704 -280.827988)
		(end 272.502376 -280.61666)
		(width 0.20066)
		(layer "F.Cu")
		(net "M_C_CPU0_SA_DQ<29>")
	)
	(segment
		(start 277.072598 -280.61666)
		(end 276.647656 -280.191718)
		(width 0.20066)
		(layer "F.Cu")
		(net "M_C_CPU0_SA_DQ<29>")
	)
	(segment
		(start 273.218148 -280.827988)
		(end 272.713704 -280.827988)
		(width 0.20066)
		(layer "F.Cu")
		(net "M_C_CPU0_SA_DQ<29>")
	)
	(segment
		(start 288.688526 -279.466294)
		(end 287.911794 -280.243026)
		(width 0.18288)
		(layer "In6.Cu")
		(net "M_C_CPU0_SA_DQ<29>")
	)
	(segment
		(start 340.712806 -263.35863)
		(end 340.706964 -263.361932)
		(width 0.088646)
		(layer "In6.Cu")
		(net "M_C_CPU0_SA_DQ<29>")
	)
	(segment
		(start 331.592174 -264.68451)
		(end 331.592174 -265.022584)
		(width 0.088646)
		(layer "In6.Cu")
		(net "M_C_CPU0_SA_DQ<29>")
	)
	(segment
		(start 336.951574 -263.3599)
		(end 336.947764 -263.361932)
		(width 0.088646)
		(layer "In6.Cu")
		(net "M_C_CPU0_SA_DQ<29>")
	)
	(segment
		(start 299.76826 -275.94179)
		(end 298.049188 -275.94179)
		(width 0.18288)
		(layer "In6.Cu")
		(net "M_C_CPU0_SA_DQ<29>")
	)
	(segment
		(start 340.706964 -263.361932)
		(end 340.701122 -263.365488)
		(width 0.088646)
		(layer "In6.Cu")
		(net "M_C_CPU0_SA_DQ<29>")
	)
	(segment
		(start 310.670702 -273.265138)
		(end 307.352192 -273.265138)
		(width 0.18288)
		(layer "In6.Cu")
		(net "M_C_CPU0_SA_DQ<29>")
	)
	(segment
		(start 332.15961 -264.117074)
		(end 331.592174 -264.68451)
		(width 0.088646)
		(layer "In6.Cu")
		(net "M_C_CPU0_SA_DQ<29>")
	)
	(segment
		(start 342.592406 -263.35863)
		(end 342.586564 -263.361932)
		(width 0.088646)
		(layer "In6.Cu")
		(net "M_C_CPU0_SA_DQ<29>")
	)
	(segment
		(start 332.264512 -263.577578)
		(end 332.15961 -263.68248)
		(width 0.088646)
		(layer "In6.Cu")
		(net "M_C_CPU0_SA_DQ<29>")
	)
	(segment
		(start 282.497276 -281.482292)
		(end 282.497276 -281.224482)
		(width 0.18288)
		(layer "In6.Cu")
		(net "M_C_CPU0_SA_DQ<29>")
	)
	(segment
		(start 281.298396 -281.665172)
		(end 281.115516 -281.482292)
		(width 0.18288)
		(layer "In6.Cu")
		(net "M_C_CPU0_SA_DQ<29>")
	)
	(segment
		(start 284.41015 -281.041602)
		(end 283.371036 -281.041602)
		(width 0.18288)
		(layer "In6.Cu")
		(net "M_C_CPU0_SA_DQ<29>")
	)
	(segment
		(start 283.005276 -281.665172)
		(end 282.680156 -281.665172)
		(width 0.18288)
		(layer "In6.Cu")
		(net "M_C_CPU0_SA_DQ<29>")
	)
	(segment
		(start 281.989276 -281.041602)
		(end 281.806396 -281.224482)
		(width 0.18288)
		(layer "In6.Cu")
		(net "M_C_CPU0_SA_DQ<29>")
	)
	(segment
		(start 326.752712 -266.556236)
		(end 321.62623 -266.556236)
		(width 0.18288)
		(layer "In6.Cu")
		(net "M_C_CPU0_SA_DQ<29>")
	)
	(segment
		(start 281.806396 -281.224482)
		(end 281.806396 -281.482292)
		(width 0.18288)
		(layer "In6.Cu")
		(net "M_C_CPU0_SA_DQ<29>")
	)
	(segment
		(start 281.115516 -281.482292)
		(end 281.115516 -281.224482)
		(width 0.18288)
		(layer "In6.Cu")
		(net "M_C_CPU0_SA_DQ<29>")
	)
	(segment
		(start 331.592174 -265.022584)
		(end 331.38237 -265.232388)
		(width 0.088646)
		(layer "In6.Cu")
		(net "M_C_CPU0_SA_DQ<29>")
	)
	(segment
		(start 341.646764 -263.361932)
		(end 341.640922 -263.365488)
		(width 0.088646)
		(layer "In6.Cu")
		(net "M_C_CPU0_SA_DQ<29>")
	)
	(segment
		(start 306.688236 -273.929094)
		(end 303.303686 -273.929094)
		(width 0.18288)
		(layer "In6.Cu")
		(net "M_C_CPU0_SA_DQ<29>")
	)
	(segment
		(start 332.15961 -263.68248)
		(end 332.15961 -264.117074)
		(width 0.088646)
		(layer "In6.Cu")
		(net "M_C_CPU0_SA_DQ<29>")
	)
	(segment
		(start 343.713816 -263.686544)
		(end 344.02649 -263.686544)
		(width 0.088646)
		(layer "In6.Cu")
		(net "M_C_CPU0_SA_DQ<29>")
	)
	(segment
		(start 313.017916 -272.394426)
		(end 311.541414 -272.394426)
		(width 0.18288)
		(layer "In6.Cu")
		(net "M_C_CPU0_SA_DQ<29>")
	)
	(segment
		(start 343.532206 -263.35863)
		(end 343.526364 -263.361932)
		(width 0.088646)
		(layer "In6.Cu")
		(net "M_C_CPU0_SA_DQ<29>")
	)
	(segment
		(start 287.911794 -280.243026)
		(end 285.208726 -280.243026)
		(width 0.18288)
		(layer "In6.Cu")
		(net "M_C_CPU0_SA_DQ<29>")
	)
	(segment
		(start 313.441842 -271.9705)
		(end 313.017916 -272.394426)
		(width 0.18288)
		(layer "In6.Cu")
		(net "M_C_CPU0_SA_DQ<29>")
	)
	(segment
		(start 281.115516 -281.224482)
		(end 280.932636 -281.041602)
		(width 0.18288)
		(layer "In6.Cu")
		(net "M_C_CPU0_SA_DQ<29>")
	)
	(segment
		(start 339.767164 -263.361932)
		(end 339.761322 -263.365488)
		(width 0.088646)
		(layer "In6.Cu")
		(net "M_C_CPU0_SA_DQ<29>")
	)
	(segment
		(start 303.303686 -273.929094)
		(end 302.646842 -274.585938)
		(width 0.18288)
		(layer "In6.Cu")
		(net "M_C_CPU0_SA_DQ<29>")
	)
	(segment
		(start 318.2747 -267.9446)
		(end 314.2488 -271.9705)
		(width 0.18288)
		(layer "In6.Cu")
		(net "M_C_CPU0_SA_DQ<29>")
	)
	(segment
		(start 329.948794 -265.232388)
		(end 326.752712 -266.556236)
		(width 0.18288)
		(layer "In6.Cu")
		(net "M_C_CPU0_SA_DQ<29>")
	)
	(segment
		(start 283.188156 -281.224482)
		(end 283.188156 -281.482292)
		(width 0.18288)
		(layer "In6.Cu")
		(net "M_C_CPU0_SA_DQ<29>")
	)
	(segment
		(start 321.62623 -266.556236)
		(end 318.2747 -267.9446)
		(width 0.18288)
		(layer "In6.Cu")
		(net "M_C_CPU0_SA_DQ<29>")
	)
	(segment
		(start 282.497276 -281.224482)
		(end 282.314396 -281.041602)
		(width 0.18288)
		(layer "In6.Cu")
		(net "M_C_CPU0_SA_DQ<29>")
	)
	(segment
		(start 339.773006 -263.35863)
		(end 339.767164 -263.361932)
		(width 0.088646)
		(layer "In6.Cu")
		(net "M_C_CPU0_SA_DQ<29>")
	)
	(segment
		(start 281.623516 -281.665172)
		(end 281.298396 -281.665172)
		(width 0.18288)
		(layer "In6.Cu")
		(net "M_C_CPU0_SA_DQ<29>")
	)
	(segment
		(start 297.199304 -276.791674)
		(end 292.838378 -276.791674)
		(width 0.18288)
		(layer "In6.Cu")
		(net "M_C_CPU0_SA_DQ<29>")
	)
	(segment
		(start 281.806396 -281.482292)
		(end 281.623516 -281.665172)
		(width 0.18288)
		(layer "In6.Cu")
		(net "M_C_CPU0_SA_DQ<29>")
	)
	(segment
		(start 280.932636 -281.041602)
		(end 280.241756 -281.041602)
		(width 0.18288)
		(layer "In6.Cu")
		(net "M_C_CPU0_SA_DQ<29>")
	)
	(segment
		(start 341.652606 -263.35863)
		(end 341.646764 -263.361932)
		(width 0.088646)
		(layer "In6.Cu")
		(net "M_C_CPU0_SA_DQ<29>")
	)
	(segment
		(start 282.314396 -281.041602)
		(end 281.989276 -281.041602)
		(width 0.18288)
		(layer "In6.Cu")
		(net "M_C_CPU0_SA_DQ<29>")
	)
	(segment
		(start 331.38237 -265.232388)
		(end 330.979272 -265.232388)
		(width 0.088646)
		(layer "In6.Cu")
		(net "M_C_CPU0_SA_DQ<29>")
	)
	(segment
		(start 314.2488 -271.9705)
		(end 313.441842 -271.9705)
		(width 0.18288)
		(layer "In6.Cu")
		(net "M_C_CPU0_SA_DQ<29>")
	)
	(segment
		(start 301.124112 -274.585938)
		(end 299.76826 -275.94179)
		(width 0.18288)
		(layer "In6.Cu")
		(net "M_C_CPU0_SA_DQ<29>")
	)
	(segment
		(start 336.947764 -263.361932)
		(end 336.941922 -263.365488)
		(width 0.088646)
		(layer "In6.Cu")
		(net "M_C_CPU0_SA_DQ<29>")
	)
	(segment
		(start 292.838378 -276.791674)
		(end 290.163758 -279.466294)
		(width 0.18288)
		(layer "In6.Cu")
		(net "M_C_CPU0_SA_DQ<29>")
	)
	(segment
		(start 343.526364 -263.361932)
		(end 343.520522 -263.365488)
		(width 0.088646)
		(layer "In6.Cu")
		(net "M_C_CPU0_SA_DQ<29>")
	)
	(segment
		(start 344.02649 -263.686544)
		(end 344.083894 -263.628886)
		(width 0.088646)
		(layer "In6.Cu")
		(net "M_C_CPU0_SA_DQ<29>")
	)
	(segment
		(start 337.891882 -263.359392)
		(end 337.887564 -263.361932)
		(width 0.088646)
		(layer "In6.Cu")
		(net "M_C_CPU0_SA_DQ<29>")
	)
	(segment
		(start 282.680156 -281.665172)
		(end 282.497276 -281.482292)
		(width 0.18288)
		(layer "In6.Cu")
		(net "M_C_CPU0_SA_DQ<29>")
	)
	(segment
		(start 338.833206 -263.35863)
		(end 338.827364 -263.361932)
		(width 0.088646)
		(layer "In6.Cu")
		(net "M_C_CPU0_SA_DQ<29>")
	)
	(segment
		(start 302.646842 -274.585938)
		(end 301.124112 -274.585938)
		(width 0.18288)
		(layer "In6.Cu")
		(net "M_C_CPU0_SA_DQ<29>")
	)
	(segment
		(start 298.049188 -275.94179)
		(end 297.199304 -276.791674)
		(width 0.18288)
		(layer "In6.Cu")
		(net "M_C_CPU0_SA_DQ<29>")
	)
	(segment
		(start 342.586564 -263.361932)
		(end 342.580722 -263.365488)
		(width 0.088646)
		(layer "In6.Cu")
		(net "M_C_CPU0_SA_DQ<29>")
	)
	(segment
		(start 336.382614 -263.361932)
		(end 336.38236 -263.362186)
		(width 0.088646)
		(layer "In6.Cu")
		(net "M_C_CPU0_SA_DQ<29>")
	)
	(segment
		(start 285.208726 -280.243026)
		(end 284.41015 -281.041602)
		(width 0.18288)
		(layer "In6.Cu")
		(net "M_C_CPU0_SA_DQ<29>")
	)
	(segment
		(start 338.827364 -263.361932)
		(end 338.821522 -263.365488)
		(width 0.088646)
		(layer "In6.Cu")
		(net "M_C_CPU0_SA_DQ<29>")
	)
	(segment
		(start 283.371036 -281.041602)
		(end 283.188156 -281.224482)
		(width 0.18288)
		(layer "In6.Cu")
		(net "M_C_CPU0_SA_DQ<29>")
	)
	(segment
		(start 290.163758 -279.466294)
		(end 288.688526 -279.466294)
		(width 0.18288)
		(layer "In6.Cu")
		(net "M_C_CPU0_SA_DQ<29>")
	)
	(segment
		(start 307.352192 -273.265138)
		(end 306.688236 -273.929094)
		(width 0.18288)
		(layer "In6.Cu")
		(net "M_C_CPU0_SA_DQ<29>")
	)
	(segment
		(start 330.979272 -265.232388)
		(end 329.948794 -265.232388)
		(width 0.18288)
		(layer "In6.Cu")
		(net "M_C_CPU0_SA_DQ<29>")
	)
	(segment
		(start 280.241756 -281.041602)
		(end 279.816814 -280.61666)
		(width 0.18288)
		(layer "In6.Cu")
		(net "M_C_CPU0_SA_DQ<29>")
	)
	(segment
		(start 283.188156 -281.482292)
		(end 283.005276 -281.665172)
		(width 0.18288)
		(layer "In6.Cu")
		(net "M_C_CPU0_SA_DQ<29>")
	)
	(segment
		(start 311.541414 -272.394426)
		(end 310.670702 -273.265138)
		(width 0.18288)
		(layer "In6.Cu")
		(net "M_C_CPU0_SA_DQ<29>")
	)
	(arc
		(start 332.784958 -263.424924)
		(mid 332.505218 -263.434744)
		(end 332.264512 -263.577578)
		(width 0.088646)
		(layer "In6.Cu")
		(net "M_C_CPU0_SA_DQ<29>")
	)
	(arc
		(start 342.580722 -263.365488)
		(mid 342.300587 -263.437771)
		(end 342.021414 -263.361932)
		(width 0.088646)
		(layer "In6.Cu")
		(net "M_C_CPU0_SA_DQ<29>")
	)
	(arc
		(start 333.56296 -263.362186)
		(mid 333.375762 -263.312043)
		(end 333.188564 -263.362186)
		(width 0.088646)
		(layer "In6.Cu")
		(net "M_C_CPU0_SA_DQ<29>")
	)
	(arc
		(start 339.202014 -263.361932)
		(mid 339.01806 -263.311803)
		(end 338.833206 -263.35863)
		(width 0.088646)
		(layer "In6.Cu")
		(net "M_C_CPU0_SA_DQ<29>")
	)
	(arc
		(start 335.44256 -263.362186)
		(mid 335.255362 -263.312043)
		(end 335.068164 -263.362186)
		(width 0.088646)
		(layer "In6.Cu")
		(net "M_C_CPU0_SA_DQ<29>")
	)
	(arc
		(start 341.640922 -263.365488)
		(mid 341.360787 -263.437771)
		(end 341.081614 -263.361932)
		(width 0.088646)
		(layer "In6.Cu")
		(net "M_C_CPU0_SA_DQ<29>")
	)
	(arc
		(start 339.761322 -263.365488)
		(mid 339.481187 -263.437771)
		(end 339.202014 -263.361932)
		(width 0.088646)
		(layer "In6.Cu")
		(net "M_C_CPU0_SA_DQ<29>")
	)
	(arc
		(start 343.901014 -263.361932)
		(mid 343.71706 -263.311803)
		(end 343.532206 -263.35863)
		(width 0.088646)
		(layer "In6.Cu")
		(net "M_C_CPU0_SA_DQ<29>")
	)
	(arc
		(start 342.961214 -263.361932)
		(mid 342.77726 -263.311803)
		(end 342.592406 -263.35863)
		(width 0.088646)
		(layer "In6.Cu")
		(net "M_C_CPU0_SA_DQ<29>")
	)
	(arc
		(start 336.38236 -263.362186)
		(mid 336.195162 -263.312043)
		(end 336.007964 -263.362186)
		(width 0.088646)
		(layer "In6.Cu")
		(net "M_C_CPU0_SA_DQ<29>")
	)
	(arc
		(start 337.322414 -263.361932)
		(mid 337.137264 -263.311828)
		(end 336.951574 -263.3599)
		(width 0.088646)
		(layer "In6.Cu")
		(net "M_C_CPU0_SA_DQ<29>")
	)
	(arc
		(start 338.262214 -263.361932)
		(mid 338.077377 -263.311671)
		(end 337.891882 -263.359392)
		(width 0.088646)
		(layer "In6.Cu")
		(net "M_C_CPU0_SA_DQ<29>")
	)
	(arc
		(start 342.021414 -263.361932)
		(mid 341.83746 -263.311803)
		(end 341.652606 -263.35863)
		(width 0.088646)
		(layer "In6.Cu")
		(net "M_C_CPU0_SA_DQ<29>")
	)
	(arc
		(start 341.081614 -263.361932)
		(mid 340.89766 -263.311803)
		(end 340.712806 -263.35863)
		(width 0.088646)
		(layer "In6.Cu")
		(net "M_C_CPU0_SA_DQ<29>")
	)
	(arc
		(start 340.701122 -263.365488)
		(mid 340.420987 -263.437771)
		(end 340.141814 -263.361932)
		(width 0.088646)
		(layer "In6.Cu")
		(net "M_C_CPU0_SA_DQ<29>")
	)
	(arc
		(start 333.188564 -263.362186)
		(mid 332.992624 -263.431232)
		(end 332.784958 -263.424924)
		(width 0.088646)
		(layer "In6.Cu")
		(net "M_C_CPU0_SA_DQ<29>")
	)
	(arc
		(start 340.141814 -263.361932)
		(mid 339.95786 -263.311803)
		(end 339.773006 -263.35863)
		(width 0.088646)
		(layer "In6.Cu")
		(net "M_C_CPU0_SA_DQ<29>")
	)
	(arc
		(start 336.007964 -263.362186)
		(mid 335.725262 -263.437928)
		(end 335.44256 -263.362186)
		(width 0.088646)
		(layer "In6.Cu")
		(net "M_C_CPU0_SA_DQ<29>")
	)
	(arc
		(start 337.887564 -263.361932)
		(mid 337.605006 -263.437581)
		(end 337.322414 -263.361932)
		(width 0.088646)
		(layer "In6.Cu")
		(net "M_C_CPU0_SA_DQ<29>")
	)
	(arc
		(start 336.941922 -263.365488)
		(mid 336.661787 -263.437771)
		(end 336.382614 -263.361932)
		(width 0.088646)
		(layer "In6.Cu")
		(net "M_C_CPU0_SA_DQ<29>")
	)
	(arc
		(start 334.128364 -263.362186)
		(mid 333.845662 -263.437928)
		(end 333.56296 -263.362186)
		(width 0.088646)
		(layer "In6.Cu")
		(net "M_C_CPU0_SA_DQ<29>")
	)
	(arc
		(start 344.083894 -263.628886)
		(mid 344.022802 -263.474602)
		(end 343.901014 -263.361932)
		(width 0.088646)
		(layer "In6.Cu")
		(net "M_C_CPU0_SA_DQ<29>")
	)
	(arc
		(start 334.50276 -263.362186)
		(mid 334.315562 -263.312043)
		(end 334.128364 -263.362186)
		(width 0.088646)
		(layer "In6.Cu")
		(net "M_C_CPU0_SA_DQ<29>")
	)
	(arc
		(start 343.520522 -263.365488)
		(mid 343.240387 -263.437771)
		(end 342.961214 -263.361932)
		(width 0.088646)
		(layer "In6.Cu")
		(net "M_C_CPU0_SA_DQ<29>")
	)
	(arc
		(start 335.068164 -263.362186)
		(mid 334.785462 -263.437928)
		(end 334.50276 -263.362186)
		(width 0.088646)
		(layer "In6.Cu")
		(net "M_C_CPU0_SA_DQ<29>")
	)
	(arc
		(start 338.821522 -263.365488)
		(mid 338.541387 -263.437771)
		(end 338.262214 -263.361932)
		(width 0.088646)
		(layer "In6.Cu")
		(net "M_C_CPU0_SA_DQ<29>")
	)
	(segment
		(start 279.816814 -282.316682)
		(end 278.711914 -282.316682)
		(width 0.20066)
		(layer "F.Cu")
		(net "M_C_CPU0_SA_DQ<28>")
	)
	(segment
		(start 276.917912 -281.89174)
		(end 276.469094 -281.89174)
		(width 0.20066)
		(layer "F.Cu")
		(net "M_C_CPU0_SA_DQ<28>")
	)
	(segment
		(start 343.243662 -263.964674)
		(end 343.243662 -264.50036)
		(width 0.20066)
		(layer "F.Cu")
		(net "M_C_CPU0_SA_DQ<28>")
	)
	(segment
		(start 274.143978 -281.883612)
		(end 273.58213 -281.883612)
		(width 0.20066)
		(layer "F.Cu")
		(net "M_C_CPU0_SA_DQ<28>")
	)
	(segment
		(start 277.342854 -282.316682)
		(end 276.917912 -281.89174)
		(width 0.20066)
		(layer "F.Cu")
		(net "M_C_CPU0_SA_DQ<28>")
	)
	(segment
		(start 272.741136 -282.555442)
		(end 272.502376 -282.316682)
		(width 0.20066)
		(layer "F.Cu")
		(net "M_C_CPU0_SA_DQ<28>")
	)
	(segment
		(start 274.152106 -281.89174)
		(end 274.143978 -281.883612)
		(width 0.101854)
		(layer "F.Cu")
		(net "M_C_CPU0_SA_DQ<28>")
	)
	(segment
		(start 274.40001 -281.89174)
		(end 274.152106 -281.89174)
		(width 0.101854)
		(layer "F.Cu")
		(net "M_C_CPU0_SA_DQ<28>")
	)
	(segment
		(start 273.37258 -282.382722)
		(end 273.19986 -282.555442)
		(width 0.20066)
		(layer "F.Cu")
		(net "M_C_CPU0_SA_DQ<28>")
	)
	(segment
		(start 343.243916 -263.96442)
		(end 343.243662 -263.964674)
		(width 0.20066)
		(layer "F.Cu")
		(net "M_C_CPU0_SA_DQ<28>")
	)
	(segment
		(start 278.711914 -282.316682)
		(end 277.342854 -282.316682)
		(width 0.20066)
		(layer "F.Cu")
		(net "M_C_CPU0_SA_DQ<28>")
	)
	(segment
		(start 273.37258 -282.093162)
		(end 273.37258 -282.382722)
		(width 0.20066)
		(layer "F.Cu")
		(net "M_C_CPU0_SA_DQ<28>")
	)
	(segment
		(start 273.19986 -282.555442)
		(end 272.741136 -282.555442)
		(width 0.20066)
		(layer "F.Cu")
		(net "M_C_CPU0_SA_DQ<28>")
	)
	(segment
		(start 272.502376 -282.316682)
		(end 271.168114 -282.316682)
		(width 0.20066)
		(layer "F.Cu")
		(net "M_C_CPU0_SA_DQ<28>")
	)
	(segment
		(start 276.469094 -281.89174)
		(end 274.40001 -281.89174)
		(width 0.1016)
		(layer "F.Cu")
		(net "M_C_CPU0_SA_DQ<28>")
	)
	(segment
		(start 273.58213 -281.883612)
		(end 273.37258 -282.093162)
		(width 0.20066)
		(layer "F.Cu")
		(net "M_C_CPU0_SA_DQ<28>")
	)
	(segment
		(start 343.243662 -264.50036)
		(end 342.872568 -264.399522)
		(width 0.088646)
		(layer "In6.Cu")
		(net "M_C_CPU0_SA_DQ<28>")
	)
	(segment
		(start 330.979272 -266.337796)
		(end 329.936856 -266.337796)
		(width 0.18288)
		(layer "In6.Cu")
		(net "M_C_CPU0_SA_DQ<28>")
	)
	(segment
		(start 332.453742 -264.754106)
		(end 332.05039 -265.157458)
		(width 0.088646)
		(layer "In6.Cu")
		(net "M_C_CPU0_SA_DQ<28>")
	)
	(segment
		(start 313.484514 -273.614642)
		(end 312.050176 -275.04898)
		(width 0.18288)
		(layer "In6.Cu")
		(net "M_C_CPU0_SA_DQ<28>")
	)
	(segment
		(start 284.197044 -282.741878)
		(end 283.719016 -282.741878)
		(width 0.18288)
		(layer "In6.Cu")
		(net "M_C_CPU0_SA_DQ<28>")
	)
	(segment
		(start 332.640686 -264.235184)
		(end 332.453742 -264.422128)
		(width 0.088646)
		(layer "In6.Cu")
		(net "M_C_CPU0_SA_DQ<28>")
	)
	(segment
		(start 332.05039 -265.770614)
		(end 331.483208 -266.337796)
		(width 0.088646)
		(layer "In6.Cu")
		(net "M_C_CPU0_SA_DQ<28>")
	)
	(segment
		(start 312.050176 -275.04898)
		(end 303.734724 -275.04898)
		(width 0.18288)
		(layer "In6.Cu")
		(net "M_C_CPU0_SA_DQ<28>")
	)
	(segment
		(start 292.711378 -279.024842)
		(end 291.645594 -280.090626)
		(width 0.18288)
		(layer "In6.Cu")
		(net "M_C_CPU0_SA_DQ<28>")
	)
	(segment
		(start 281.81173 -283.28874)
		(end 281.62885 -283.47162)
		(width 0.18288)
		(layer "In6.Cu")
		(net "M_C_CPU0_SA_DQ<28>")
	)
	(segment
		(start 331.483208 -266.337796)
		(end 330.979272 -266.337796)
		(width 0.088646)
		(layer "In6.Cu")
		(net "M_C_CPU0_SA_DQ<28>")
	)
	(segment
		(start 283.719016 -282.741878)
		(end 283.718762 -282.741624)
		(width 0.18288)
		(layer "In6.Cu")
		(net "M_C_CPU0_SA_DQ<28>")
	)
	(segment
		(start 297.199304 -278.491696)
		(end 294.285416 -278.491696)
		(width 0.18288)
		(layer "In6.Cu")
		(net "M_C_CPU0_SA_DQ<28>")
	)
	(segment
		(start 298.049188 -277.641812)
		(end 297.199304 -278.491696)
		(width 0.18288)
		(layer "In6.Cu")
		(net "M_C_CPU0_SA_DQ<28>")
	)
	(segment
		(start 342.116664 -264.176002)
		(end 342.101932 -264.184638)
		(width 0.088646)
		(layer "In6.Cu")
		(net "M_C_CPU0_SA_DQ<28>")
	)
	(segment
		(start 288.488374 -281.264614)
		(end 287.011364 -282.741624)
		(width 0.18288)
		(layer "In6.Cu")
		(net "M_C_CPU0_SA_DQ<28>")
	)
	(segment
		(start 314.335668 -273.614642)
		(end 313.484514 -273.614642)
		(width 0.18288)
		(layer "In6.Cu")
		(net "M_C_CPU0_SA_DQ<28>")
	)
	(segment
		(start 280.241756 -282.741624)
		(end 279.816814 -282.316682)
		(width 0.18288)
		(layer "In6.Cu")
		(net "M_C_CPU0_SA_DQ<28>")
	)
	(segment
		(start 342.872568 -264.399522)
		(end 342.49106 -264.176002)
		(width 0.088646)
		(layer "In6.Cu")
		(net "M_C_CPU0_SA_DQ<28>")
	)
	(segment
		(start 300.524926 -277.641812)
		(end 298.049188 -277.641812)
		(width 0.18288)
		(layer "In6.Cu")
		(net "M_C_CPU0_SA_DQ<28>")
	)
	(segment
		(start 302.938942 -275.844762)
		(end 302.321976 -275.844762)
		(width 0.18288)
		(layer "In6.Cu")
		(net "M_C_CPU0_SA_DQ<28>")
	)
	(segment
		(start 293.75227 -279.024842)
		(end 292.711378 -279.024842)
		(width 0.18288)
		(layer "In6.Cu")
		(net "M_C_CPU0_SA_DQ<28>")
	)
	(segment
		(start 339.297518 -264.176002)
		(end 339.287104 -264.182098)
		(width 0.088646)
		(layer "In6.Cu")
		(net "M_C_CPU0_SA_DQ<28>")
	)
	(segment
		(start 340.237064 -264.176002)
		(end 340.22665 -264.182098)
		(width 0.088646)
		(layer "In6.Cu")
		(net "M_C_CPU0_SA_DQ<28>")
	)
	(segment
		(start 326.943974 -267.577316)
		(end 322.471288 -267.577316)
		(width 0.18288)
		(layer "In6.Cu")
		(net "M_C_CPU0_SA_DQ<28>")
	)
	(segment
		(start 281.62885 -283.47162)
		(end 281.30373 -283.47162)
		(width 0.18288)
		(layer "In6.Cu")
		(net "M_C_CPU0_SA_DQ<28>")
	)
	(segment
		(start 283.718762 -282.741624)
		(end 281.99461 -282.741624)
		(width 0.18288)
		(layer "In6.Cu")
		(net "M_C_CPU0_SA_DQ<28>")
	)
	(segment
		(start 281.81173 -282.924504)
		(end 281.81173 -283.28874)
		(width 0.18288)
		(layer "In6.Cu")
		(net "M_C_CPU0_SA_DQ<28>")
	)
	(segment
		(start 303.734724 -275.04898)
		(end 302.938942 -275.844762)
		(width 0.18288)
		(layer "In6.Cu")
		(net "M_C_CPU0_SA_DQ<28>")
	)
	(segment
		(start 289.993578 -281.264614)
		(end 288.488374 -281.264614)
		(width 0.18288)
		(layer "In6.Cu")
		(net "M_C_CPU0_SA_DQ<28>")
	)
	(segment
		(start 329.936856 -266.337796)
		(end 326.943974 -267.577316)
		(width 0.18288)
		(layer "In6.Cu")
		(net "M_C_CPU0_SA_DQ<28>")
	)
	(segment
		(start 322.471288 -267.577316)
		(end 318.889126 -269.061184)
		(width 0.18288)
		(layer "In6.Cu")
		(net "M_C_CPU0_SA_DQ<28>")
	)
	(segment
		(start 280.93797 -282.741624)
		(end 280.241756 -282.741624)
		(width 0.18288)
		(layer "In6.Cu")
		(net "M_C_CPU0_SA_DQ<28>")
	)
	(segment
		(start 281.12085 -283.28874)
		(end 281.12085 -282.924504)
		(width 0.18288)
		(layer "In6.Cu")
		(net "M_C_CPU0_SA_DQ<28>")
	)
	(segment
		(start 291.645594 -280.090626)
		(end 291.167566 -280.090626)
		(width 0.18288)
		(layer "In6.Cu")
		(net "M_C_CPU0_SA_DQ<28>")
	)
	(segment
		(start 287.011364 -282.741624)
		(end 284.197298 -282.741624)
		(width 0.18288)
		(layer "In6.Cu")
		(net "M_C_CPU0_SA_DQ<28>")
	)
	(segment
		(start 332.453742 -264.422128)
		(end 332.453742 -264.754106)
		(width 0.088646)
		(layer "In6.Cu")
		(net "M_C_CPU0_SA_DQ<28>")
	)
	(segment
		(start 284.197298 -282.741624)
		(end 284.197044 -282.741878)
		(width 0.18288)
		(layer "In6.Cu")
		(net "M_C_CPU0_SA_DQ<28>")
	)
	(segment
		(start 281.12085 -282.924504)
		(end 280.93797 -282.741624)
		(width 0.18288)
		(layer "In6.Cu")
		(net "M_C_CPU0_SA_DQ<28>")
	)
	(segment
		(start 281.30373 -283.47162)
		(end 281.12085 -283.28874)
		(width 0.18288)
		(layer "In6.Cu")
		(net "M_C_CPU0_SA_DQ<28>")
	)
	(segment
		(start 318.889126 -269.061184)
		(end 314.335668 -273.614642)
		(width 0.18288)
		(layer "In6.Cu")
		(net "M_C_CPU0_SA_DQ<28>")
	)
	(segment
		(start 294.285416 -278.491696)
		(end 293.75227 -279.024842)
		(width 0.18288)
		(layer "In6.Cu")
		(net "M_C_CPU0_SA_DQ<28>")
	)
	(segment
		(start 291.167566 -280.090626)
		(end 289.993578 -281.264614)
		(width 0.18288)
		(layer "In6.Cu")
		(net "M_C_CPU0_SA_DQ<28>")
	)
	(segment
		(start 341.176864 -264.176002)
		(end 341.162132 -264.184638)
		(width 0.088646)
		(layer "In6.Cu")
		(net "M_C_CPU0_SA_DQ<28>")
	)
	(segment
		(start 332.05039 -265.157458)
		(end 332.05039 -265.770614)
		(width 0.088646)
		(layer "In6.Cu")
		(net "M_C_CPU0_SA_DQ<28>")
	)
	(segment
		(start 302.321976 -275.844762)
		(end 300.524926 -277.641812)
		(width 0.18288)
		(layer "In6.Cu")
		(net "M_C_CPU0_SA_DQ<28>")
	)
	(segment
		(start 281.99461 -282.741624)
		(end 281.81173 -282.924504)
		(width 0.18288)
		(layer "In6.Cu")
		(net "M_C_CPU0_SA_DQ<28>")
	)
	(arc
		(start 336.85226 -264.176002)
		(mid 336.665062 -264.125859)
		(end 336.477864 -264.176002)
		(width 0.088646)
		(layer "In6.Cu")
		(net "M_C_CPU0_SA_DQ<28>")
	)
	(arc
		(start 333.09306 -264.176002)
		(mid 332.905862 -264.125859)
		(end 332.718664 -264.176002)
		(width 0.088646)
		(layer "In6.Cu")
		(net "M_C_CPU0_SA_DQ<28>")
	)
	(arc
		(start 338.357464 -264.176002)
		(mid 338.074762 -264.251778)
		(end 337.79206 -264.176002)
		(width 0.088646)
		(layer "In6.Cu")
		(net "M_C_CPU0_SA_DQ<28>")
	)
	(arc
		(start 339.671914 -264.176002)
		(mid 339.484716 -264.125859)
		(end 339.297518 -264.176002)
		(width 0.088646)
		(layer "In6.Cu")
		(net "M_C_CPU0_SA_DQ<28>")
	)
	(arc
		(start 337.417664 -264.176002)
		(mid 337.134962 -264.251778)
		(end 336.85226 -264.176002)
		(width 0.088646)
		(layer "In6.Cu")
		(net "M_C_CPU0_SA_DQ<28>")
	)
	(arc
		(start 332.718664 -264.176002)
		(mid 332.677734 -264.203035)
		(end 332.640686 -264.235184)
		(width 0.088646)
		(layer "In6.Cu")
		(net "M_C_CPU0_SA_DQ<28>")
	)
	(arc
		(start 334.97266 -264.176002)
		(mid 334.785462 -264.125859)
		(end 334.598264 -264.176002)
		(width 0.088646)
		(layer "In6.Cu")
		(net "M_C_CPU0_SA_DQ<28>")
	)
	(arc
		(start 335.91246 -264.176002)
		(mid 335.725262 -264.125859)
		(end 335.538064 -264.176002)
		(width 0.088646)
		(layer "In6.Cu")
		(net "M_C_CPU0_SA_DQ<28>")
	)
	(arc
		(start 342.101932 -264.184638)
		(mid 341.825457 -264.251958)
		(end 341.55126 -264.176002)
		(width 0.088646)
		(layer "In6.Cu")
		(net "M_C_CPU0_SA_DQ<28>")
	)
	(arc
		(start 334.03286 -264.176002)
		(mid 333.845662 -264.125859)
		(end 333.658464 -264.176002)
		(width 0.088646)
		(layer "In6.Cu")
		(net "M_C_CPU0_SA_DQ<28>")
	)
	(arc
		(start 341.55126 -264.176002)
		(mid 341.364062 -264.125859)
		(end 341.176864 -264.176002)
		(width 0.088646)
		(layer "In6.Cu")
		(net "M_C_CPU0_SA_DQ<28>")
	)
	(arc
		(start 340.61146 -264.176002)
		(mid 340.424262 -264.125859)
		(end 340.237064 -264.176002)
		(width 0.088646)
		(layer "In6.Cu")
		(net "M_C_CPU0_SA_DQ<28>")
	)
	(arc
		(start 334.598264 -264.176002)
		(mid 334.315562 -264.251778)
		(end 334.03286 -264.176002)
		(width 0.088646)
		(layer "In6.Cu")
		(net "M_C_CPU0_SA_DQ<28>")
	)
	(arc
		(start 336.477864 -264.176002)
		(mid 336.195162 -264.251778)
		(end 335.91246 -264.176002)
		(width 0.088646)
		(layer "In6.Cu")
		(net "M_C_CPU0_SA_DQ<28>")
	)
	(arc
		(start 341.162132 -264.184638)
		(mid 340.885657 -264.251958)
		(end 340.61146 -264.176002)
		(width 0.088646)
		(layer "In6.Cu")
		(net "M_C_CPU0_SA_DQ<28>")
	)
	(arc
		(start 340.22665 -264.182098)
		(mid 339.948472 -264.251821)
		(end 339.671914 -264.176002)
		(width 0.088646)
		(layer "In6.Cu")
		(net "M_C_CPU0_SA_DQ<28>")
	)
	(arc
		(start 342.49106 -264.176002)
		(mid 342.303862 -264.125859)
		(end 342.116664 -264.176002)
		(width 0.088646)
		(layer "In6.Cu")
		(net "M_C_CPU0_SA_DQ<28>")
	)
	(arc
		(start 335.538064 -264.176002)
		(mid 335.255362 -264.251778)
		(end 334.97266 -264.176002)
		(width 0.088646)
		(layer "In6.Cu")
		(net "M_C_CPU0_SA_DQ<28>")
	)
	(arc
		(start 333.658464 -264.176002)
		(mid 333.375762 -264.251778)
		(end 333.09306 -264.176002)
		(width 0.088646)
		(layer "In6.Cu")
		(net "M_C_CPU0_SA_DQ<28>")
	)
	(arc
		(start 339.287104 -264.182098)
		(mid 339.008672 -264.251944)
		(end 338.73186 -264.176002)
		(width 0.088646)
		(layer "In6.Cu")
		(net "M_C_CPU0_SA_DQ<28>")
	)
	(arc
		(start 338.73186 -264.176002)
		(mid 338.544662 -264.125859)
		(end 338.357464 -264.176002)
		(width 0.088646)
		(layer "In6.Cu")
		(net "M_C_CPU0_SA_DQ<28>")
	)
	(arc
		(start 337.79206 -264.176002)
		(mid 337.604862 -264.125859)
		(end 337.417664 -264.176002)
		(width 0.088646)
		(layer "In6.Cu")
		(net "M_C_CPU0_SA_DQ<28>")
	)
	(segment
		(start 280.73477 -285.712408)
		(end 280.606246 -285.840932)
		(width 0.20066)
		(layer "F.Cu")
		(net "M_C_CPU0_SA_DQ<27>")
	)
	(segment
		(start 281.788362 -285.924244)
		(end 281.34183 -285.924244)
		(width 0.20066)
		(layer "F.Cu")
		(net "M_C_CPU0_SA_DQ<27>")
	)
	(segment
		(start 279.912826 -286.141668)
		(end 277.839932 -286.141668)
		(width 0.1016)
		(layer "F.Cu")
		(net "M_C_CPU0_SA_DQ<27>")
	)
	(segment
		(start 283.916882 -285.716726)
		(end 282.811982 -285.716726)
		(width 0.20066)
		(layer "F.Cu")
		(net "M_C_CPU0_SA_DQ<27>")
	)
	(segment
		(start 345.123262 -265.592306)
		(end 345.123262 -266.128246)
		(width 0.20066)
		(layer "F.Cu")
		(net "M_C_CPU0_SA_DQ<27>")
	)
	(segment
		(start 277.839932 -286.141668)
		(end 277.601934 -286.141668)
		(width 0.101854)
		(layer "F.Cu")
		(net "M_C_CPU0_SA_DQ<27>")
	)
	(segment
		(start 345.123516 -265.592306)
		(end 345.123262 -265.592306)
		(width 0.20066)
		(layer "F.Cu")
		(net "M_C_CPU0_SA_DQ<27>")
	)
	(segment
		(start 277.091394 -285.84271)
		(end 276.96541 -285.716726)
		(width 0.20066)
		(layer "F.Cu")
		(net "M_C_CPU0_SA_DQ<27>")
	)
	(segment
		(start 280.606246 -285.99257)
		(end 280.457148 -286.141668)
		(width 0.20066)
		(layer "F.Cu")
		(net "M_C_CPU0_SA_DQ<27>")
	)
	(segment
		(start 281.99588 -285.716726)
		(end 281.788362 -285.924244)
		(width 0.20066)
		(layer "F.Cu")
		(net "M_C_CPU0_SA_DQ<27>")
	)
	(segment
		(start 277.58771 -286.155892)
		(end 277.233888 -286.155892)
		(width 0.20066)
		(layer "F.Cu")
		(net "M_C_CPU0_SA_DQ<27>")
	)
	(segment
		(start 277.091394 -286.013398)
		(end 277.091394 -285.84271)
		(width 0.20066)
		(layer "F.Cu")
		(net "M_C_CPU0_SA_DQ<27>")
	)
	(segment
		(start 282.811982 -285.716726)
		(end 281.99588 -285.716726)
		(width 0.20066)
		(layer "F.Cu")
		(net "M_C_CPU0_SA_DQ<27>")
	)
	(segment
		(start 276.96541 -285.716726)
		(end 275.268182 -285.716726)
		(width 0.20066)
		(layer "F.Cu")
		(net "M_C_CPU0_SA_DQ<27>")
	)
	(segment
		(start 280.606246 -285.840932)
		(end 280.606246 -285.99257)
		(width 0.20066)
		(layer "F.Cu")
		(net "M_C_CPU0_SA_DQ<27>")
	)
	(segment
		(start 280.457148 -286.141668)
		(end 279.912826 -286.141668)
		(width 0.20066)
		(layer "F.Cu")
		(net "M_C_CPU0_SA_DQ<27>")
	)
	(segment
		(start 277.233888 -286.155892)
		(end 277.091394 -286.013398)
		(width 0.20066)
		(layer "F.Cu")
		(net "M_C_CPU0_SA_DQ<27>")
	)
	(segment
		(start 281.34183 -285.924244)
		(end 281.129994 -285.712408)
		(width 0.20066)
		(layer "F.Cu")
		(net "M_C_CPU0_SA_DQ<27>")
	)
	(segment
		(start 277.601934 -286.141668)
		(end 277.58771 -286.155892)
		(width 0.101854)
		(layer "F.Cu")
		(net "M_C_CPU0_SA_DQ<27>")
	)
	(segment
		(start 281.129994 -285.712408)
		(end 280.73477 -285.712408)
		(width 0.20066)
		(layer "F.Cu")
		(net "M_C_CPU0_SA_DQ<27>")
	)
	(segment
		(start 332.39075 -267.471398)
		(end 332.39075 -267.913612)
		(width 0.088646)
		(layer "In6.Cu")
		(net "M_C_CPU0_SA_DQ<27>")
	)
	(segment
		(start 309.221886 -279.341326)
		(end 309.039006 -279.158446)
		(width 0.18288)
		(layer "In6.Cu")
		(net "M_C_CPU0_SA_DQ<27>")
	)
	(segment
		(start 309.039006 -278.42591)
		(end 308.856126 -278.24303)
		(width 0.18288)
		(layer "In6.Cu")
		(net "M_C_CPU0_SA_DQ<27>")
	)
	(segment
		(start 342.622632 -266.376404)
		(end 342.49106 -266.45235)
		(width 0.088646)
		(layer "In6.Cu")
		(net "M_C_CPU0_SA_DQ<27>")
	)
	(segment
		(start 285.572454 -286.231838)
		(end 284.431994 -286.231838)
		(width 0.18288)
		(layer "In6.Cu")
		(net "M_C_CPU0_SA_DQ<27>")
	)
	(segment
		(start 297.628564 -282.741624)
		(end 294.37838 -282.741624)
		(width 0.18288)
		(layer "In6.Cu")
		(net "M_C_CPU0_SA_DQ<27>")
	)
	(segment
		(start 300.98492 -281.456384)
		(end 300.98492 -281.70886)
		(width 0.18288)
		(layer "In6.Cu")
		(net "M_C_CPU0_SA_DQ<27>")
	)
	(segment
		(start 342.116664 -266.45235)
		(end 342.101932 -266.443714)
		(width 0.088646)
		(layer "In6.Cu")
		(net "M_C_CPU0_SA_DQ<27>")
	)
	(segment
		(start 308.165246 -279.341326)
		(end 304.90795 -279.341326)
		(width 0.18288)
		(layer "In6.Cu")
		(net "M_C_CPU0_SA_DQ<27>")
	)
	(segment
		(start 341.176864 -266.45235)
		(end 341.162132 -266.443714)
		(width 0.088646)
		(layer "In6.Cu")
		(net "M_C_CPU0_SA_DQ<27>")
	)
	(segment
		(start 332.39075 -267.913612)
		(end 331.824838 -268.479524)
		(width 0.088646)
		(layer "In6.Cu")
		(net "M_C_CPU0_SA_DQ<27>")
	)
	(segment
		(start 286.263334 -285.529528)
		(end 285.938214 -285.529528)
		(width 0.18288)
		(layer "In6.Cu")
		(net "M_C_CPU0_SA_DQ<27>")
	)
	(segment
		(start 301.6758 -281.456384)
		(end 301.49292 -281.273504)
		(width 0.18288)
		(layer "In6.Cu")
		(net "M_C_CPU0_SA_DQ<27>")
	)
	(segment
		(start 291.162994 -283.800804)
		(end 289.63112 -285.332678)
		(width 0.18288)
		(layer "In6.Cu")
		(net "M_C_CPU0_SA_DQ<27>")
	)
	(segment
		(start 304.90795 -279.341326)
		(end 303.281588 -280.967688)
		(width 0.18288)
		(layer "In6.Cu")
		(net "M_C_CPU0_SA_DQ<27>")
	)
	(segment
		(start 303.281588 -281.251152)
		(end 302.641 -281.89174)
		(width 0.18288)
		(layer "In6.Cu")
		(net "M_C_CPU0_SA_DQ<27>")
	)
	(segment
		(start 288.587942 -285.332678)
		(end 287.688782 -286.231838)
		(width 0.18288)
		(layer "In6.Cu")
		(net "M_C_CPU0_SA_DQ<27>")
	)
	(segment
		(start 332.506066 -267.356082)
		(end 332.39075 -267.471398)
		(width 0.088646)
		(layer "In6.Cu")
		(net "M_C_CPU0_SA_DQ<27>")
	)
	(segment
		(start 289.63112 -285.332678)
		(end 288.587942 -285.332678)
		(width 0.18288)
		(layer "In6.Cu")
		(net "M_C_CPU0_SA_DQ<27>")
	)
	(segment
		(start 342.796622 -266.055602)
		(end 342.768174 -266.124436)
		(width 0.088646)
		(layer "In6.Cu")
		(net "M_C_CPU0_SA_DQ<27>")
	)
	(segment
		(start 294.37838 -282.741624)
		(end 293.3192 -283.800804)
		(width 0.18288)
		(layer "In6.Cu")
		(net "M_C_CPU0_SA_DQ<27>")
	)
	(segment
		(start 285.755334 -286.048958)
		(end 285.572454 -286.231838)
		(width 0.18288)
		(layer "In6.Cu")
		(net "M_C_CPU0_SA_DQ<27>")
	)
	(segment
		(start 308.856126 -278.24303)
		(end 308.531006 -278.24303)
		(width 0.18288)
		(layer "In6.Cu")
		(net "M_C_CPU0_SA_DQ<27>")
	)
	(segment
		(start 293.3192 -283.800804)
		(end 291.162994 -283.800804)
		(width 0.18288)
		(layer "In6.Cu")
		(net "M_C_CPU0_SA_DQ<27>")
	)
	(segment
		(start 300.98492 -281.70886)
		(end 300.80204 -281.89174)
		(width 0.18288)
		(layer "In6.Cu")
		(net "M_C_CPU0_SA_DQ<27>")
	)
	(segment
		(start 302.641 -281.89174)
		(end 301.85868 -281.89174)
		(width 0.18288)
		(layer "In6.Cu")
		(net "M_C_CPU0_SA_DQ<27>")
	)
	(segment
		(start 332.810612 -266.931902)
		(end 332.810612 -266.941808)
		(width 0.088646)
		(layer "In6.Cu")
		(net "M_C_CPU0_SA_DQ<27>")
	)
	(segment
		(start 308.348126 -279.158446)
		(end 308.165246 -279.341326)
		(width 0.18288)
		(layer "In6.Cu")
		(net "M_C_CPU0_SA_DQ<27>")
	)
	(segment
		(start 312.62828 -278.465026)
		(end 311.323482 -278.465026)
		(width 0.18288)
		(layer "In6.Cu")
		(net "M_C_CPU0_SA_DQ<27>")
	)
	(segment
		(start 286.629094 -286.231838)
		(end 286.446214 -286.048958)
		(width 0.18288)
		(layer "In6.Cu")
		(net "M_C_CPU0_SA_DQ<27>")
	)
	(segment
		(start 330.336144 -268.479524)
		(end 319.92189 -272.792444)
		(width 0.18288)
		(layer "In6.Cu")
		(net "M_C_CPU0_SA_DQ<27>")
	)
	(segment
		(start 343.436956 -265.806936)
		(end 343.425272 -265.800332)
		(width 0.088646)
		(layer "In6.Cu")
		(net "M_C_CPU0_SA_DQ<27>")
	)
	(segment
		(start 298.478448 -281.89174)
		(end 297.628564 -282.741624)
		(width 0.18288)
		(layer "In6.Cu")
		(net "M_C_CPU0_SA_DQ<27>")
	)
	(segment
		(start 301.85868 -281.89174)
		(end 301.6758 -281.70886)
		(width 0.18288)
		(layer "In6.Cu")
		(net "M_C_CPU0_SA_DQ<27>")
	)
	(segment
		(start 310.447182 -279.341326)
		(end 309.221886 -279.341326)
		(width 0.18288)
		(layer "In6.Cu")
		(net "M_C_CPU0_SA_DQ<27>")
	)
	(segment
		(start 308.348126 -278.42591)
		(end 308.348126 -279.158446)
		(width 0.18288)
		(layer "In6.Cu")
		(net "M_C_CPU0_SA_DQ<27>")
	)
	(segment
		(start 330.979272 -268.479524)
		(end 330.336144 -268.479524)
		(width 0.18288)
		(layer "In6.Cu")
		(net "M_C_CPU0_SA_DQ<27>")
	)
	(segment
		(start 344.78976 -266.040616)
		(end 344.365072 -265.800332)
		(width 0.088646)
		(layer "In6.Cu")
		(net "M_C_CPU0_SA_DQ<27>")
	)
	(segment
		(start 319.92189 -272.792444)
		(end 315.000386 -277.713948)
		(width 0.18288)
		(layer "In6.Cu")
		(net "M_C_CPU0_SA_DQ<27>")
	)
	(segment
		(start 300.80204 -281.89174)
		(end 298.478448 -281.89174)
		(width 0.18288)
		(layer "In6.Cu")
		(net "M_C_CPU0_SA_DQ<27>")
	)
	(segment
		(start 301.49292 -281.273504)
		(end 301.1678 -281.273504)
		(width 0.18288)
		(layer "In6.Cu")
		(net "M_C_CPU0_SA_DQ<27>")
	)
	(segment
		(start 286.446214 -286.048958)
		(end 286.446214 -285.712408)
		(width 0.18288)
		(layer "In6.Cu")
		(net "M_C_CPU0_SA_DQ<27>")
	)
	(segment
		(start 285.938214 -285.529528)
		(end 285.755334 -285.712408)
		(width 0.18288)
		(layer "In6.Cu")
		(net "M_C_CPU0_SA_DQ<27>")
	)
	(segment
		(start 311.323482 -278.465026)
		(end 310.447182 -279.341326)
		(width 0.18288)
		(layer "In6.Cu")
		(net "M_C_CPU0_SA_DQ<27>")
	)
	(segment
		(start 285.755334 -285.712408)
		(end 285.755334 -286.048958)
		(width 0.18288)
		(layer "In6.Cu")
		(net "M_C_CPU0_SA_DQ<27>")
	)
	(segment
		(start 315.000386 -277.713948)
		(end 313.379358 -277.713948)
		(width 0.18288)
		(layer "In6.Cu")
		(net "M_C_CPU0_SA_DQ<27>")
	)
	(segment
		(start 284.431994 -286.231838)
		(end 283.916882 -285.716726)
		(width 0.18288)
		(layer "In6.Cu")
		(net "M_C_CPU0_SA_DQ<27>")
	)
	(segment
		(start 313.379358 -277.713948)
		(end 312.62828 -278.465026)
		(width 0.18288)
		(layer "In6.Cu")
		(net "M_C_CPU0_SA_DQ<27>")
	)
	(segment
		(start 309.039006 -279.158446)
		(end 309.039006 -278.42591)
		(width 0.18288)
		(layer "In6.Cu")
		(net "M_C_CPU0_SA_DQ<27>")
	)
	(segment
		(start 301.1678 -281.273504)
		(end 300.98492 -281.456384)
		(width 0.18288)
		(layer "In6.Cu")
		(net "M_C_CPU0_SA_DQ<27>")
	)
	(segment
		(start 308.531006 -278.24303)
		(end 308.348126 -278.42591)
		(width 0.18288)
		(layer "In6.Cu")
		(net "M_C_CPU0_SA_DQ<27>")
	)
	(segment
		(start 287.688782 -286.231838)
		(end 286.629094 -286.231838)
		(width 0.18288)
		(layer "In6.Cu")
		(net "M_C_CPU0_SA_DQ<27>")
	)
	(segment
		(start 301.6758 -281.70886)
		(end 301.6758 -281.456384)
		(width 0.18288)
		(layer "In6.Cu")
		(net "M_C_CPU0_SA_DQ<27>")
	)
	(segment
		(start 331.824838 -268.479524)
		(end 330.979272 -268.479524)
		(width 0.088646)
		(layer "In6.Cu")
		(net "M_C_CPU0_SA_DQ<27>")
	)
	(segment
		(start 286.446214 -285.712408)
		(end 286.263334 -285.529528)
		(width 0.18288)
		(layer "In6.Cu")
		(net "M_C_CPU0_SA_DQ<27>")
	)
	(segment
		(start 303.281588 -280.967688)
		(end 303.281588 -281.251152)
		(width 0.18288)
		(layer "In6.Cu")
		(net "M_C_CPU0_SA_DQ<27>")
	)
	(segment
		(start 340.237064 -266.45235)
		(end 340.222332 -266.443714)
		(width 0.088646)
		(layer "In6.Cu")
		(net "M_C_CPU0_SA_DQ<27>")
	)
	(arc
		(start 344.365072 -265.800332)
		(mid 344.180217 -265.753382)
		(end 343.996264 -265.803634)
		(width 0.088646)
		(layer "In6.Cu")
		(net "M_C_CPU0_SA_DQ<27>")
	)
	(arc
		(start 343.425272 -265.800332)
		(mid 343.240417 -265.753382)
		(end 343.056464 -265.803634)
		(width 0.088646)
		(layer "In6.Cu")
		(net "M_C_CPU0_SA_DQ<27>")
	)
	(arc
		(start 334.97266 -266.45235)
		(mid 334.785462 -266.502527)
		(end 334.598264 -266.45235)
		(width 0.088646)
		(layer "In6.Cu")
		(net "M_C_CPU0_SA_DQ<27>")
	)
	(arc
		(start 333.658464 -266.45235)
		(mid 333.375762 -266.376574)
		(end 333.09306 -266.45235)
		(width 0.088646)
		(layer "In6.Cu")
		(net "M_C_CPU0_SA_DQ<27>")
	)
	(arc
		(start 343.056464 -265.803634)
		(mid 342.958038 -265.869386)
		(end 342.869012 -265.947398)
		(width 0.088646)
		(layer "In6.Cu")
		(net "M_C_CPU0_SA_DQ<27>")
	)
	(arc
		(start 338.73186 -266.45235)
		(mid 338.544662 -266.502527)
		(end 338.357464 -266.45235)
		(width 0.088646)
		(layer "In6.Cu")
		(net "M_C_CPU0_SA_DQ<27>")
	)
	(arc
		(start 340.222332 -266.443714)
		(mid 339.945857 -266.376394)
		(end 339.67166 -266.45235)
		(width 0.088646)
		(layer "In6.Cu")
		(net "M_C_CPU0_SA_DQ<27>")
	)
	(arc
		(start 339.297264 -266.45235)
		(mid 339.014562 -266.376574)
		(end 338.73186 -266.45235)
		(width 0.088646)
		(layer "In6.Cu")
		(net "M_C_CPU0_SA_DQ<27>")
	)
	(arc
		(start 332.63205 -267.261086)
		(mid 332.565726 -267.304166)
		(end 332.506066 -267.356082)
		(width 0.088646)
		(layer "In6.Cu")
		(net "M_C_CPU0_SA_DQ<27>")
	)
	(arc
		(start 341.162132 -266.443714)
		(mid 340.885657 -266.376394)
		(end 340.61146 -266.45235)
		(width 0.088646)
		(layer "In6.Cu")
		(net "M_C_CPU0_SA_DQ<27>")
	)
	(arc
		(start 342.49106 -266.45235)
		(mid 342.303862 -266.502527)
		(end 342.116664 -266.45235)
		(width 0.088646)
		(layer "In6.Cu")
		(net "M_C_CPU0_SA_DQ<27>")
	)
	(arc
		(start 341.55126 -266.45235)
		(mid 341.364062 -266.502527)
		(end 341.176864 -266.45235)
		(width 0.088646)
		(layer "In6.Cu")
		(net "M_C_CPU0_SA_DQ<27>")
	)
	(arc
		(start 335.91246 -266.45235)
		(mid 335.725262 -266.502527)
		(end 335.538064 -266.45235)
		(width 0.088646)
		(layer "In6.Cu")
		(net "M_C_CPU0_SA_DQ<27>")
	)
	(arc
		(start 334.598264 -266.45235)
		(mid 334.315562 -266.376574)
		(end 334.03286 -266.45235)
		(width 0.088646)
		(layer "In6.Cu")
		(net "M_C_CPU0_SA_DQ<27>")
	)
	(arc
		(start 336.477864 -266.45235)
		(mid 336.195162 -266.376574)
		(end 335.91246 -266.45235)
		(width 0.088646)
		(layer "In6.Cu")
		(net "M_C_CPU0_SA_DQ<27>")
	)
	(arc
		(start 333.09306 -266.45235)
		(mid 332.888725 -266.654955)
		(end 332.810612 -266.931902)
		(width 0.088646)
		(layer "In6.Cu")
		(net "M_C_CPU0_SA_DQ<27>")
	)
	(arc
		(start 345.123262 -266.128246)
		(mid 344.950847 -266.105996)
		(end 344.78976 -266.040616)
		(width 0.088646)
		(layer "In6.Cu")
		(net "M_C_CPU0_SA_DQ<27>")
	)
	(arc
		(start 342.101932 -266.443714)
		(mid 341.825457 -266.376394)
		(end 341.55126 -266.45235)
		(width 0.088646)
		(layer "In6.Cu")
		(net "M_C_CPU0_SA_DQ<27>")
	)
	(arc
		(start 334.03286 -266.45235)
		(mid 333.845662 -266.502527)
		(end 333.658464 -266.45235)
		(width 0.088646)
		(layer "In6.Cu")
		(net "M_C_CPU0_SA_DQ<27>")
	)
	(arc
		(start 335.538064 -266.45235)
		(mid 335.255362 -266.376574)
		(end 334.97266 -266.45235)
		(width 0.088646)
		(layer "In6.Cu")
		(net "M_C_CPU0_SA_DQ<27>")
	)
	(arc
		(start 340.61146 -266.45235)
		(mid 340.424262 -266.502527)
		(end 340.237064 -266.45235)
		(width 0.088646)
		(layer "In6.Cu")
		(net "M_C_CPU0_SA_DQ<27>")
	)
	(arc
		(start 342.869012 -265.947398)
		(mid 342.827487 -265.997935)
		(end 342.796622 -266.055602)
		(width 0.088646)
		(layer "In6.Cu")
		(net "M_C_CPU0_SA_DQ<27>")
	)
	(arc
		(start 337.79206 -266.45235)
		(mid 337.604862 -266.502527)
		(end 337.417664 -266.45235)
		(width 0.088646)
		(layer "In6.Cu")
		(net "M_C_CPU0_SA_DQ<27>")
	)
	(arc
		(start 343.996264 -265.803634)
		(mid 343.717061 -265.879274)
		(end 343.436956 -265.806936)
		(width 0.088646)
		(layer "In6.Cu")
		(net "M_C_CPU0_SA_DQ<27>")
	)
	(arc
		(start 339.67166 -266.45235)
		(mid 339.484462 -266.502527)
		(end 339.297264 -266.45235)
		(width 0.088646)
		(layer "In6.Cu")
		(net "M_C_CPU0_SA_DQ<27>")
	)
	(arc
		(start 342.768174 -266.124436)
		(mid 342.72917 -266.269921)
		(end 342.622632 -266.376404)
		(width 0.088646)
		(layer "In6.Cu")
		(net "M_C_CPU0_SA_DQ<27>")
	)
	(arc
		(start 338.357464 -266.45235)
		(mid 338.074762 -266.376574)
		(end 337.79206 -266.45235)
		(width 0.088646)
		(layer "In6.Cu")
		(net "M_C_CPU0_SA_DQ<27>")
	)
	(arc
		(start 337.417664 -266.45235)
		(mid 337.134962 -266.376574)
		(end 336.85226 -266.45235)
		(width 0.088646)
		(layer "In6.Cu")
		(net "M_C_CPU0_SA_DQ<27>")
	)
	(arc
		(start 336.85226 -266.45235)
		(mid 336.665062 -266.502527)
		(end 336.477864 -266.45235)
		(width 0.088646)
		(layer "In6.Cu")
		(net "M_C_CPU0_SA_DQ<27>")
	)
	(arc
		(start 332.810612 -266.941808)
		(mid 332.762933 -267.124708)
		(end 332.63205 -267.261086)
		(width 0.088646)
		(layer "In6.Cu")
		(net "M_C_CPU0_SA_DQ<27>")
	)
	(segment
		(start 283.916882 -287.416748)
		(end 282.811982 -287.416748)
		(width 0.20066)
		(layer "F.Cu")
		(net "M_C_CPU0_SA_DQ<26>")
	)
	(segment
		(start 280.689558 -287.13557)
		(end 280.545794 -286.991806)
		(width 0.20066)
		(layer "F.Cu")
		(net "M_C_CPU0_SA_DQ<26>")
	)
	(segment
		(start 280.689558 -287.461198)
		(end 280.689558 -287.13557)
		(width 0.20066)
		(layer "F.Cu")
		(net "M_C_CPU0_SA_DQ<26>")
	)
	(segment
		(start 344.653616 -266.406122)
		(end 344.653616 -266.941808)
		(width 0.20066)
		(layer "F.Cu")
		(net "M_C_CPU0_SA_DQ<26>")
	)
	(segment
		(start 277.59787 -286.991806)
		(end 277.58771 -286.981646)
		(width 0.101854)
		(layer "F.Cu")
		(net "M_C_CPU0_SA_DQ<26>")
	)
	(segment
		(start 277.58771 -286.981646)
		(end 276.850348 -286.981646)
		(width 0.20066)
		(layer "F.Cu")
		(net "M_C_CPU0_SA_DQ<26>")
	)
	(segment
		(start 277.852886 -286.991806)
		(end 277.59787 -286.991806)
		(width 0.101854)
		(layer "F.Cu")
		(net "M_C_CPU0_SA_DQ<26>")
	)
	(segment
		(start 281.285442 -287.628584)
		(end 280.856944 -287.628584)
		(width 0.20066)
		(layer "F.Cu")
		(net "M_C_CPU0_SA_DQ<26>")
	)
	(segment
		(start 280.545794 -286.991806)
		(end 279.912826 -286.991806)
		(width 0.20066)
		(layer "F.Cu")
		(net "M_C_CPU0_SA_DQ<26>")
	)
	(segment
		(start 279.912826 -286.991806)
		(end 277.852886 -286.991806)
		(width 0.1016)
		(layer "F.Cu")
		(net "M_C_CPU0_SA_DQ<26>")
	)
	(segment
		(start 280.856944 -287.628584)
		(end 280.689558 -287.461198)
		(width 0.20066)
		(layer "F.Cu")
		(net "M_C_CPU0_SA_DQ<26>")
	)
	(segment
		(start 276.415246 -287.416748)
		(end 275.268182 -287.416748)
		(width 0.20066)
		(layer "F.Cu")
		(net "M_C_CPU0_SA_DQ<26>")
	)
	(segment
		(start 276.850348 -286.981646)
		(end 276.415246 -287.416748)
		(width 0.20066)
		(layer "F.Cu")
		(net "M_C_CPU0_SA_DQ<26>")
	)
	(segment
		(start 281.497278 -287.416748)
		(end 281.285442 -287.628584)
		(width 0.20066)
		(layer "F.Cu")
		(net "M_C_CPU0_SA_DQ<26>")
	)
	(segment
		(start 282.811982 -287.416748)
		(end 281.497278 -287.416748)
		(width 0.20066)
		(layer "F.Cu")
		(net "M_C_CPU0_SA_DQ<26>")
	)
	(segment
		(start 344.653362 -266.405868)
		(end 344.653616 -266.406122)
		(width 0.20066)
		(layer "F.Cu")
		(net "M_C_CPU0_SA_DQ<26>")
	)
	(segment
		(start 300.31182 -283.951934)
		(end 299.828712 -283.951934)
		(width 0.18288)
		(layer "In6.Cu")
		(net "M_C_CPU0_SA_DQ<26>")
	)
	(segment
		(start 299.828712 -283.951934)
		(end 299.339 -284.441646)
		(width 0.18288)
		(layer "In6.Cu")
		(net "M_C_CPU0_SA_DQ<26>")
	)
	(segment
		(start 302.571658 -283.951934)
		(end 301.32528 -283.951934)
		(width 0.18288)
		(layer "In6.Cu")
		(net "M_C_CPU0_SA_DQ<26>")
	)
	(segment
		(start 314.786264 -279.475184)
		(end 313.492642 -279.475184)
		(width 0.18288)
		(layer "In6.Cu")
		(net "M_C_CPU0_SA_DQ<26>")
	)
	(segment
		(start 344.653616 -266.941808)
		(end 344.02649 -266.469622)
		(width 0.088646)
		(layer "In6.Cu")
		(net "M_C_CPU0_SA_DQ<26>")
	)
	(segment
		(start 290.663122 -285.75)
		(end 290.663122 -286.008572)
		(width 0.18288)
		(layer "In6.Cu")
		(net "M_C_CPU0_SA_DQ<26>")
	)
	(segment
		(start 338.827364 -267.266166)
		(end 338.812632 -267.25753)
		(width 0.088646)
		(layer "In6.Cu")
		(net "M_C_CPU0_SA_DQ<26>")
	)
	(segment
		(start 342.970104 -267.261086)
		(end 342.961214 -267.266166)
		(width 0.088646)
		(layer "In6.Cu")
		(net "M_C_CPU0_SA_DQ<26>")
	)
	(segment
		(start 288.742628 -287.006792)
		(end 287.886394 -287.863026)
		(width 0.18288)
		(layer "In6.Cu")
		(net "M_C_CPU0_SA_DQ<26>")
	)
	(segment
		(start 297.179492 -284.441646)
		(end 296.98188 -284.244034)
		(width 0.18288)
		(layer "In6.Cu")
		(net "M_C_CPU0_SA_DQ<26>")
	)
	(segment
		(start 290.913312 -286.258762)
		(end 290.913312 -286.517334)
		(width 0.18288)
		(layer "In6.Cu")
		(net "M_C_CPU0_SA_DQ<26>")
	)
	(segment
		(start 300.47184 -284.619192)
		(end 300.47184 -284.111954)
		(width 0.18288)
		(layer "In6.Cu")
		(net "M_C_CPU0_SA_DQ<26>")
	)
	(segment
		(start 290.423854 -287.006792)
		(end 288.742628 -287.006792)
		(width 0.18288)
		(layer "In6.Cu")
		(net "M_C_CPU0_SA_DQ<26>")
	)
	(segment
		(start 300.47184 -284.111954)
		(end 300.31182 -283.951934)
		(width 0.18288)
		(layer "In6.Cu")
		(net "M_C_CPU0_SA_DQ<26>")
	)
	(segment
		(start 310.590184 -280.805636)
		(end 307.563266 -280.805636)
		(width 0.18288)
		(layer "In6.Cu")
		(net "M_C_CPU0_SA_DQ<26>")
	)
	(segment
		(start 344.02649 -266.469622)
		(end 343.996264 -266.45235)
		(width 0.088646)
		(layer "In6.Cu")
		(net "M_C_CPU0_SA_DQ<26>")
	)
	(segment
		(start 320.722244 -273.539204)
		(end 314.786264 -279.475184)
		(width 0.18288)
		(layer "In6.Cu")
		(net "M_C_CPU0_SA_DQ<26>")
	)
	(segment
		(start 296.98188 -284.244034)
		(end 296.487088 -284.244034)
		(width 0.18288)
		(layer "In6.Cu")
		(net "M_C_CPU0_SA_DQ<26>")
	)
	(segment
		(start 296.487088 -284.244034)
		(end 295.439338 -285.291784)
		(width 0.18288)
		(layer "In6.Cu")
		(net "M_C_CPU0_SA_DQ<26>")
	)
	(segment
		(start 291.402008 -285.770066)
		(end 291.151818 -285.519876)
		(width 0.18288)
		(layer "In6.Cu")
		(net "M_C_CPU0_SA_DQ<26>")
	)
	(segment
		(start 330.979272 -269.576804)
		(end 330.294234 -269.576804)
		(width 0.18288)
		(layer "In6.Cu")
		(net "M_C_CPU0_SA_DQ<26>")
	)
	(segment
		(start 331.56906 -269.576804)
		(end 330.979272 -269.576804)
		(width 0.088646)
		(layer "In6.Cu")
		(net "M_C_CPU0_SA_DQ<26>")
	)
	(segment
		(start 301.00524 -284.779212)
		(end 300.63186 -284.779212)
		(width 0.18288)
		(layer "In6.Cu")
		(net "M_C_CPU0_SA_DQ<26>")
	)
	(segment
		(start 339.212174 -267.26007)
		(end 339.20176 -267.266166)
		(width 0.088646)
		(layer "In6.Cu")
		(net "M_C_CPU0_SA_DQ<26>")
	)
	(segment
		(start 307.236876 -281.132026)
		(end 305.691032 -281.132026)
		(width 0.18288)
		(layer "In6.Cu")
		(net "M_C_CPU0_SA_DQ<26>")
	)
	(segment
		(start 291.151818 -285.519876)
		(end 290.893246 -285.519876)
		(width 0.18288)
		(layer "In6.Cu")
		(net "M_C_CPU0_SA_DQ<26>")
	)
	(segment
		(start 312.819542 -280.148284)
		(end 311.247536 -280.148284)
		(width 0.18288)
		(layer "In6.Cu")
		(net "M_C_CPU0_SA_DQ<26>")
	)
	(segment
		(start 301.16526 -284.619192)
		(end 301.00524 -284.779212)
		(width 0.18288)
		(layer "In6.Cu")
		(net "M_C_CPU0_SA_DQ<26>")
	)
	(segment
		(start 343.996264 -266.45235)
		(end 343.981532 -266.443714)
		(width 0.088646)
		(layer "In6.Cu")
		(net "M_C_CPU0_SA_DQ<26>")
	)
	(segment
		(start 307.563266 -280.805636)
		(end 307.236876 -281.132026)
		(width 0.18288)
		(layer "In6.Cu")
		(net "M_C_CPU0_SA_DQ<26>")
	)
	(segment
		(start 341.096346 -267.25753)
		(end 341.081614 -267.266166)
		(width 0.088646)
		(layer "In6.Cu")
		(net "M_C_CPU0_SA_DQ<26>")
	)
	(segment
		(start 340.156546 -267.25753)
		(end 340.141814 -267.266166)
		(width 0.088646)
		(layer "In6.Cu")
		(net "M_C_CPU0_SA_DQ<26>")
	)
	(segment
		(start 303.172876 -283.350716)
		(end 302.571658 -283.951934)
		(width 0.18288)
		(layer "In6.Cu")
		(net "M_C_CPU0_SA_DQ<26>")
	)
	(segment
		(start 291.66058 -285.770066)
		(end 291.402008 -285.770066)
		(width 0.18288)
		(layer "In6.Cu")
		(net "M_C_CPU0_SA_DQ<26>")
	)
	(segment
		(start 337.332828 -267.26007)
		(end 337.32216 -267.266166)
		(width 0.088646)
		(layer "In6.Cu")
		(net "M_C_CPU0_SA_DQ<26>")
	)
	(segment
		(start 303.172876 -282.881832)
		(end 303.172876 -283.350716)
		(width 0.18288)
		(layer "In6.Cu")
		(net "M_C_CPU0_SA_DQ<26>")
	)
	(segment
		(start 290.663122 -286.008572)
		(end 290.913312 -286.258762)
		(width 0.18288)
		(layer "In6.Cu")
		(net "M_C_CPU0_SA_DQ<26>")
	)
	(segment
		(start 311.247536 -280.148284)
		(end 310.590184 -280.805636)
		(width 0.18288)
		(layer "In6.Cu")
		(net "M_C_CPU0_SA_DQ<26>")
	)
	(segment
		(start 290.893246 -285.519876)
		(end 290.663122 -285.75)
		(width 0.18288)
		(layer "In6.Cu")
		(net "M_C_CPU0_SA_DQ<26>")
	)
	(segment
		(start 290.913312 -286.517334)
		(end 290.423854 -287.006792)
		(width 0.18288)
		(layer "In6.Cu")
		(net "M_C_CPU0_SA_DQ<26>")
	)
	(segment
		(start 305.691032 -281.132026)
		(end 305.062382 -281.760676)
		(width 0.18288)
		(layer "In6.Cu")
		(net "M_C_CPU0_SA_DQ<26>")
	)
	(segment
		(start 330.294234 -269.576804)
		(end 320.722244 -273.539204)
		(width 0.18288)
		(layer "In6.Cu")
		(net "M_C_CPU0_SA_DQ<26>")
	)
	(segment
		(start 300.63186 -284.779212)
		(end 300.47184 -284.619192)
		(width 0.18288)
		(layer "In6.Cu")
		(net "M_C_CPU0_SA_DQ<26>")
	)
	(segment
		(start 333.280512 -267.737336)
		(end 333.280512 -267.755878)
		(width 0.088646)
		(layer "In6.Cu")
		(net "M_C_CPU0_SA_DQ<26>")
	)
	(segment
		(start 313.492642 -279.475184)
		(end 312.819542 -280.148284)
		(width 0.18288)
		(layer "In6.Cu")
		(net "M_C_CPU0_SA_DQ<26>")
	)
	(segment
		(start 292.138862 -285.291784)
		(end 291.66058 -285.770066)
		(width 0.18288)
		(layer "In6.Cu")
		(net "M_C_CPU0_SA_DQ<26>")
	)
	(segment
		(start 301.32528 -283.951934)
		(end 301.16526 -284.111954)
		(width 0.18288)
		(layer "In6.Cu")
		(net "M_C_CPU0_SA_DQ<26>")
	)
	(segment
		(start 295.439338 -285.291784)
		(end 292.138862 -285.291784)
		(width 0.18288)
		(layer "In6.Cu")
		(net "M_C_CPU0_SA_DQ<26>")
	)
	(segment
		(start 343.148666 -266.926314)
		(end 343.148666 -266.941808)
		(width 0.088646)
		(layer "In6.Cu")
		(net "M_C_CPU0_SA_DQ<26>")
	)
	(segment
		(start 299.339 -284.441646)
		(end 297.179492 -284.441646)
		(width 0.18288)
		(layer "In6.Cu")
		(net "M_C_CPU0_SA_DQ<26>")
	)
	(segment
		(start 284.36316 -287.863026)
		(end 283.916882 -287.416748)
		(width 0.18288)
		(layer "In6.Cu")
		(net "M_C_CPU0_SA_DQ<26>")
	)
	(segment
		(start 304.294032 -281.760676)
		(end 303.172876 -282.881832)
		(width 0.18288)
		(layer "In6.Cu")
		(net "M_C_CPU0_SA_DQ<26>")
	)
	(segment
		(start 305.062382 -281.760676)
		(end 304.294032 -281.760676)
		(width 0.18288)
		(layer "In6.Cu")
		(net "M_C_CPU0_SA_DQ<26>")
	)
	(segment
		(start 301.16526 -284.111954)
		(end 301.16526 -284.619192)
		(width 0.18288)
		(layer "In6.Cu")
		(net "M_C_CPU0_SA_DQ<26>")
	)
	(segment
		(start 287.886394 -287.863026)
		(end 284.36316 -287.863026)
		(width 0.18288)
		(layer "In6.Cu")
		(net "M_C_CPU0_SA_DQ<26>")
	)
	(segment
		(start 332.975966 -268.169898)
		(end 331.56906 -269.576804)
		(width 0.088646)
		(layer "In6.Cu")
		(net "M_C_CPU0_SA_DQ<26>")
	)
	(segment
		(start 342.036146 -267.25753)
		(end 342.021414 -267.266166)
		(width 0.088646)
		(layer "In6.Cu")
		(net "M_C_CPU0_SA_DQ<26>")
	)
	(arc
		(start 339.20176 -267.266166)
		(mid 339.014562 -267.316309)
		(end 338.827364 -267.266166)
		(width 0.088646)
		(layer "In6.Cu")
		(net "M_C_CPU0_SA_DQ<26>")
	)
	(arc
		(start 338.26196 -267.266166)
		(mid 338.074762 -267.316309)
		(end 337.887564 -267.266166)
		(width 0.088646)
		(layer "In6.Cu")
		(net "M_C_CPU0_SA_DQ<26>")
	)
	(arc
		(start 338.812632 -267.25753)
		(mid 338.536191 -267.190364)
		(end 338.26196 -267.266166)
		(width 0.088646)
		(layer "In6.Cu")
		(net "M_C_CPU0_SA_DQ<26>")
	)
	(arc
		(start 341.647018 -267.266166)
		(mid 341.372789 -267.190241)
		(end 341.096346 -267.25753)
		(width 0.088646)
		(layer "In6.Cu")
		(net "M_C_CPU0_SA_DQ<26>")
	)
	(arc
		(start 334.128364 -267.266166)
		(mid 333.845662 -267.190424)
		(end 333.56296 -267.266166)
		(width 0.088646)
		(layer "In6.Cu")
		(net "M_C_CPU0_SA_DQ<26>")
	)
	(arc
		(start 335.44256 -267.266166)
		(mid 335.255362 -267.316309)
		(end 335.068164 -267.266166)
		(width 0.088646)
		(layer "In6.Cu")
		(net "M_C_CPU0_SA_DQ<26>")
	)
	(arc
		(start 337.32216 -267.266166)
		(mid 337.134962 -267.316309)
		(end 336.947764 -267.266166)
		(width 0.088646)
		(layer "In6.Cu")
		(net "M_C_CPU0_SA_DQ<26>")
	)
	(arc
		(start 341.081614 -267.266166)
		(mid 340.894416 -267.316309)
		(end 340.707218 -267.266166)
		(width 0.088646)
		(layer "In6.Cu")
		(net "M_C_CPU0_SA_DQ<26>")
	)
	(arc
		(start 340.141814 -267.266166)
		(mid 339.954616 -267.316309)
		(end 339.767418 -267.266166)
		(width 0.088646)
		(layer "In6.Cu")
		(net "M_C_CPU0_SA_DQ<26>")
	)
	(arc
		(start 333.56296 -267.266166)
		(mid 333.360674 -267.465147)
		(end 333.280512 -267.737336)
		(width 0.088646)
		(layer "In6.Cu")
		(net "M_C_CPU0_SA_DQ<26>")
	)
	(arc
		(start 337.887564 -267.266166)
		(mid 337.611005 -267.190457)
		(end 337.332828 -267.26007)
		(width 0.088646)
		(layer "In6.Cu")
		(net "M_C_CPU0_SA_DQ<26>")
	)
	(arc
		(start 343.981532 -266.443714)
		(mid 343.705057 -266.376394)
		(end 343.43086 -266.45235)
		(width 0.088646)
		(layer "In6.Cu")
		(net "M_C_CPU0_SA_DQ<26>")
	)
	(arc
		(start 333.10195 -268.075156)
		(mid 333.035646 -268.118122)
		(end 332.975966 -268.169898)
		(width 0.088646)
		(layer "In6.Cu")
		(net "M_C_CPU0_SA_DQ<26>")
	)
	(arc
		(start 336.947764 -267.266166)
		(mid 336.665062 -267.190424)
		(end 336.38236 -267.266166)
		(width 0.088646)
		(layer "In6.Cu")
		(net "M_C_CPU0_SA_DQ<26>")
	)
	(arc
		(start 334.50276 -267.266166)
		(mid 334.315562 -267.316309)
		(end 334.128364 -267.266166)
		(width 0.088646)
		(layer "In6.Cu")
		(net "M_C_CPU0_SA_DQ<26>")
	)
	(arc
		(start 342.021414 -267.266166)
		(mid 341.834216 -267.316309)
		(end 341.647018 -267.266166)
		(width 0.088646)
		(layer "In6.Cu")
		(net "M_C_CPU0_SA_DQ<26>")
	)
	(arc
		(start 333.280512 -267.755878)
		(mid 333.232833 -267.938778)
		(end 333.10195 -268.075156)
		(width 0.088646)
		(layer "In6.Cu")
		(net "M_C_CPU0_SA_DQ<26>")
	)
	(arc
		(start 342.586818 -267.266166)
		(mid 342.312589 -267.190241)
		(end 342.036146 -267.25753)
		(width 0.088646)
		(layer "In6.Cu")
		(net "M_C_CPU0_SA_DQ<26>")
	)
	(arc
		(start 336.007964 -267.266166)
		(mid 335.725262 -267.190424)
		(end 335.44256 -267.266166)
		(width 0.088646)
		(layer "In6.Cu")
		(net "M_C_CPU0_SA_DQ<26>")
	)
	(arc
		(start 340.707218 -267.266166)
		(mid 340.432989 -267.190241)
		(end 340.156546 -267.25753)
		(width 0.088646)
		(layer "In6.Cu")
		(net "M_C_CPU0_SA_DQ<26>")
	)
	(arc
		(start 335.068164 -267.266166)
		(mid 334.785462 -267.190424)
		(end 334.50276 -267.266166)
		(width 0.088646)
		(layer "In6.Cu")
		(net "M_C_CPU0_SA_DQ<26>")
	)
	(arc
		(start 343.148666 -266.941808)
		(mid 343.100987 -267.124708)
		(end 342.970104 -267.261086)
		(width 0.088646)
		(layer "In6.Cu")
		(net "M_C_CPU0_SA_DQ<26>")
	)
	(arc
		(start 342.961214 -267.266166)
		(mid 342.774016 -267.316309)
		(end 342.586818 -267.266166)
		(width 0.088646)
		(layer "In6.Cu")
		(net "M_C_CPU0_SA_DQ<26>")
	)
	(arc
		(start 343.43086 -266.45235)
		(mid 343.228037 -266.652581)
		(end 343.148666 -266.926314)
		(width 0.088646)
		(layer "In6.Cu")
		(net "M_C_CPU0_SA_DQ<26>")
	)
	(arc
		(start 339.767418 -267.266166)
		(mid 339.490605 -267.19033)
		(end 339.212174 -267.26007)
		(width 0.088646)
		(layer "In6.Cu")
		(net "M_C_CPU0_SA_DQ<26>")
	)
	(arc
		(start 336.38236 -267.266166)
		(mid 336.195162 -267.316309)
		(end 336.007964 -267.266166)
		(width 0.088646)
		(layer "In6.Cu")
		(net "M_C_CPU0_SA_DQ<26>")
	)
	(segment
		(start 279.816814 -286.56661)
		(end 278.711914 -286.56661)
		(width 0.20066)
		(layer "F.Cu")
		(net "M_C_CPU0_SA_DQ<25>")
	)
	(segment
		(start 276.138386 -286.141668)
		(end 274.152868 -286.141668)
		(width 0.1016)
		(layer "F.Cu")
		(net "M_C_CPU0_SA_DQ<25>")
	)
	(segment
		(start 273.37258 -286.623506)
		(end 273.218148 -286.777938)
		(width 0.20066)
		(layer "F.Cu")
		(net "M_C_CPU0_SA_DQ<25>")
	)
	(segment
		(start 272.502376 -286.56661)
		(end 271.168114 -286.56661)
		(width 0.20066)
		(layer "F.Cu")
		(net "M_C_CPU0_SA_DQ<25>")
	)
	(segment
		(start 273.37258 -286.295338)
		(end 273.37258 -286.623506)
		(width 0.20066)
		(layer "F.Cu")
		(net "M_C_CPU0_SA_DQ<25>")
	)
	(segment
		(start 278.711914 -286.56661)
		(end 277.072598 -286.56661)
		(width 0.20066)
		(layer "F.Cu")
		(net "M_C_CPU0_SA_DQ<25>")
	)
	(segment
		(start 276.647656 -286.141668)
		(end 276.469094 -286.141668)
		(width 0.20066)
		(layer "F.Cu")
		(net "M_C_CPU0_SA_DQ<25>")
	)
	(segment
		(start 343.243662 -265.592306)
		(end 343.243662 -266.128246)
		(width 0.20066)
		(layer "F.Cu")
		(net "M_C_CPU0_SA_DQ<25>")
	)
	(segment
		(start 274.143978 -286.132778)
		(end 273.53514 -286.132778)
		(width 0.20066)
		(layer "F.Cu")
		(net "M_C_CPU0_SA_DQ<25>")
	)
	(segment
		(start 277.072598 -286.56661)
		(end 276.647656 -286.141668)
		(width 0.20066)
		(layer "F.Cu")
		(net "M_C_CPU0_SA_DQ<25>")
	)
	(segment
		(start 273.218148 -286.777938)
		(end 272.713704 -286.777938)
		(width 0.20066)
		(layer "F.Cu")
		(net "M_C_CPU0_SA_DQ<25>")
	)
	(segment
		(start 273.53514 -286.132778)
		(end 273.37258 -286.295338)
		(width 0.20066)
		(layer "F.Cu")
		(net "M_C_CPU0_SA_DQ<25>")
	)
	(segment
		(start 272.713704 -286.777938)
		(end 272.502376 -286.56661)
		(width 0.20066)
		(layer "F.Cu")
		(net "M_C_CPU0_SA_DQ<25>")
	)
	(segment
		(start 343.243916 -265.592306)
		(end 343.243662 -265.592306)
		(width 0.20066)
		(layer "F.Cu")
		(net "M_C_CPU0_SA_DQ<25>")
	)
	(segment
		(start 274.152868 -286.141668)
		(end 274.143978 -286.132778)
		(width 0.1016)
		(layer "F.Cu")
		(net "M_C_CPU0_SA_DQ<25>")
	)
	(segment
		(start 276.469094 -286.141668)
		(end 276.138386 -286.141668)
		(width 0.101854)
		(layer "F.Cu")
		(net "M_C_CPU0_SA_DQ<25>")
	)
	(segment
		(start 310.97855 -279.527254)
		(end 310.313832 -280.191972)
		(width 0.18288)
		(layer "In6.Cu")
		(net "M_C_CPU0_SA_DQ<25>")
	)
	(segment
		(start 280.968196 -286.991806)
		(end 280.24201 -286.991806)
		(width 0.18288)
		(layer "In6.Cu")
		(net "M_C_CPU0_SA_DQ<25>")
	)
	(segment
		(start 330.200508 -269.076424)
		(end 320.264282 -273.1897)
		(width 0.18288)
		(layer "In6.Cu")
		(net "M_C_CPU0_SA_DQ<25>")
	)
	(segment
		(start 330.979272 -269.076424)
		(end 330.200508 -269.076424)
		(width 0.18288)
		(layer "In6.Cu")
		(net "M_C_CPU0_SA_DQ<25>")
	)
	(segment
		(start 304.860706 -281.177746)
		(end 304.147474 -281.177746)
		(width 0.18288)
		(layer "In6.Cu")
		(net "M_C_CPU0_SA_DQ<25>")
	)
	(segment
		(start 339.212174 -266.6238)
		(end 339.20176 -266.617704)
		(width 0.088646)
		(layer "In6.Cu")
		(net "M_C_CPU0_SA_DQ<25>")
	)
	(segment
		(start 293.54907 -284.421072)
		(end 291.287454 -284.421072)
		(width 0.18288)
		(layer "In6.Cu")
		(net "M_C_CPU0_SA_DQ<25>")
	)
	(segment
		(start 289.76828 -285.940246)
		(end 288.691574 -285.940246)
		(width 0.18288)
		(layer "In6.Cu")
		(net "M_C_CPU0_SA_DQ<25>")
	)
	(segment
		(start 313.673998 -278.428704)
		(end 312.575448 -279.527254)
		(width 0.18288)
		(layer "In6.Cu")
		(net "M_C_CPU0_SA_DQ<25>")
	)
	(segment
		(start 333.188564 -266.617704)
		(end 333.17434 -266.625832)
		(width 0.088646)
		(layer "In6.Cu")
		(net "M_C_CPU0_SA_DQ<25>")
	)
	(segment
		(start 282.532836 -287.174686)
		(end 282.349956 -286.991806)
		(width 0.18288)
		(layer "In6.Cu")
		(net "M_C_CPU0_SA_DQ<25>")
	)
	(segment
		(start 291.287454 -284.421072)
		(end 289.76828 -285.940246)
		(width 0.18288)
		(layer "In6.Cu")
		(net "M_C_CPU0_SA_DQ<25>")
	)
	(segment
		(start 283.406596 -286.991806)
		(end 283.223716 -287.174686)
		(width 0.18288)
		(layer "In6.Cu")
		(net "M_C_CPU0_SA_DQ<25>")
	)
	(segment
		(start 282.024836 -286.991806)
		(end 281.841956 -287.174686)
		(width 0.18288)
		(layer "In6.Cu")
		(net "M_C_CPU0_SA_DQ<25>")
	)
	(segment
		(start 282.349956 -286.991806)
		(end 282.024836 -286.991806)
		(width 0.18288)
		(layer "In6.Cu")
		(net "M_C_CPU0_SA_DQ<25>")
	)
	(segment
		(start 342.871552 -266.452858)
		(end 342.586818 -266.61745)
		(width 0.088646)
		(layer "In6.Cu")
		(net "M_C_CPU0_SA_DQ<25>")
	)
	(segment
		(start 281.659076 -287.604454)
		(end 281.333956 -287.604454)
		(width 0.18288)
		(layer "In6.Cu")
		(net "M_C_CPU0_SA_DQ<25>")
	)
	(segment
		(start 302.583342 -282.741878)
		(end 298.503848 -282.741878)
		(width 0.18288)
		(layer "In6.Cu")
		(net "M_C_CPU0_SA_DQ<25>")
	)
	(segment
		(start 304.147474 -281.177746)
		(end 302.583342 -282.741878)
		(width 0.18288)
		(layer "In6.Cu")
		(net "M_C_CPU0_SA_DQ<25>")
	)
	(segment
		(start 280.24201 -286.991806)
		(end 279.816814 -286.56661)
		(width 0.18288)
		(layer "In6.Cu")
		(net "M_C_CPU0_SA_DQ<25>")
	)
	(segment
		(start 282.532836 -287.421574)
		(end 282.532836 -287.174686)
		(width 0.18288)
		(layer "In6.Cu")
		(net "M_C_CPU0_SA_DQ<25>")
	)
	(segment
		(start 342.586818 -266.61745)
		(end 342.586818 -266.617704)
		(width 0.088646)
		(layer "In6.Cu")
		(net "M_C_CPU0_SA_DQ<25>")
	)
	(segment
		(start 342.036146 -266.62634)
		(end 342.021414 -266.617704)
		(width 0.088646)
		(layer "In6.Cu")
		(net "M_C_CPU0_SA_DQ<25>")
	)
	(segment
		(start 281.151076 -287.421574)
		(end 281.151076 -287.174686)
		(width 0.18288)
		(layer "In6.Cu")
		(net "M_C_CPU0_SA_DQ<25>")
	)
	(segment
		(start 297.653964 -283.591762)
		(end 294.37838 -283.591762)
		(width 0.18288)
		(layer "In6.Cu")
		(net "M_C_CPU0_SA_DQ<25>")
	)
	(segment
		(start 305.84648 -280.191972)
		(end 304.860706 -281.177746)
		(width 0.18288)
		(layer "In6.Cu")
		(net "M_C_CPU0_SA_DQ<25>")
	)
	(segment
		(start 340.156546 -266.62634)
		(end 340.141814 -266.617704)
		(width 0.088646)
		(layer "In6.Cu")
		(net "M_C_CPU0_SA_DQ<25>")
	)
	(segment
		(start 282.715716 -287.604454)
		(end 282.532836 -287.421574)
		(width 0.18288)
		(layer "In6.Cu")
		(net "M_C_CPU0_SA_DQ<25>")
	)
	(segment
		(start 315.025278 -278.428704)
		(end 313.673998 -278.428704)
		(width 0.18288)
		(layer "In6.Cu")
		(net "M_C_CPU0_SA_DQ<25>")
	)
	(segment
		(start 281.151076 -287.174686)
		(end 280.968196 -286.991806)
		(width 0.18288)
		(layer "In6.Cu")
		(net "M_C_CPU0_SA_DQ<25>")
	)
	(segment
		(start 341.096346 -266.62634)
		(end 341.081614 -266.617704)
		(width 0.088646)
		(layer "In6.Cu")
		(net "M_C_CPU0_SA_DQ<25>")
	)
	(segment
		(start 288.691574 -285.940246)
		(end 287.640014 -286.991806)
		(width 0.18288)
		(layer "In6.Cu")
		(net "M_C_CPU0_SA_DQ<25>")
	)
	(segment
		(start 331.639672 -269.076424)
		(end 330.979272 -269.076424)
		(width 0.088646)
		(layer "In6.Cu")
		(net "M_C_CPU0_SA_DQ<25>")
	)
	(segment
		(start 281.333956 -287.604454)
		(end 281.151076 -287.421574)
		(width 0.18288)
		(layer "In6.Cu")
		(net "M_C_CPU0_SA_DQ<25>")
	)
	(segment
		(start 287.640014 -286.991806)
		(end 283.406596 -286.991806)
		(width 0.18288)
		(layer "In6.Cu")
		(net "M_C_CPU0_SA_DQ<25>")
	)
	(segment
		(start 343.243662 -266.128246)
		(end 343.243408 -266.128246)
		(width 0.088646)
		(layer "In6.Cu")
		(net "M_C_CPU0_SA_DQ<25>")
	)
	(segment
		(start 310.313832 -280.191972)
		(end 305.84648 -280.191972)
		(width 0.18288)
		(layer "In6.Cu")
		(net "M_C_CPU0_SA_DQ<25>")
	)
	(segment
		(start 283.223716 -287.421574)
		(end 283.040836 -287.604454)
		(width 0.18288)
		(layer "In6.Cu")
		(net "M_C_CPU0_SA_DQ<25>")
	)
	(segment
		(start 312.575448 -279.527254)
		(end 310.97855 -279.527254)
		(width 0.18288)
		(layer "In6.Cu")
		(net "M_C_CPU0_SA_DQ<25>")
	)
	(segment
		(start 294.37838 -283.591762)
		(end 293.54907 -284.421072)
		(width 0.18288)
		(layer "In6.Cu")
		(net "M_C_CPU0_SA_DQ<25>")
	)
	(segment
		(start 320.264282 -273.1897)
		(end 315.025278 -278.428704)
		(width 0.18288)
		(layer "In6.Cu")
		(net "M_C_CPU0_SA_DQ<25>")
	)
	(segment
		(start 332.640686 -268.07541)
		(end 331.639672 -269.076424)
		(width 0.088646)
		(layer "In6.Cu")
		(net "M_C_CPU0_SA_DQ<25>")
	)
	(segment
		(start 281.841956 -287.174686)
		(end 281.841956 -287.421574)
		(width 0.18288)
		(layer "In6.Cu")
		(net "M_C_CPU0_SA_DQ<25>")
	)
	(segment
		(start 281.841956 -287.421574)
		(end 281.659076 -287.604454)
		(width 0.18288)
		(layer "In6.Cu")
		(net "M_C_CPU0_SA_DQ<25>")
	)
	(segment
		(start 343.243408 -266.128246)
		(end 343.075006 -266.296648)
		(width 0.088646)
		(layer "In6.Cu")
		(net "M_C_CPU0_SA_DQ<25>")
	)
	(segment
		(start 283.040836 -287.604454)
		(end 282.715716 -287.604454)
		(width 0.18288)
		(layer "In6.Cu")
		(net "M_C_CPU0_SA_DQ<25>")
	)
	(segment
		(start 298.503848 -282.741878)
		(end 297.653964 -283.591762)
		(width 0.18288)
		(layer "In6.Cu")
		(net "M_C_CPU0_SA_DQ<25>")
	)
	(segment
		(start 283.223716 -287.174686)
		(end 283.223716 -287.421574)
		(width 0.18288)
		(layer "In6.Cu")
		(net "M_C_CPU0_SA_DQ<25>")
	)
	(segment
		(start 333.001112 -266.941808)
		(end 333.001112 -266.96035)
		(width 0.088646)
		(layer "In6.Cu")
		(net "M_C_CPU0_SA_DQ<25>")
	)
	(segment
		(start 332.640686 -267.490702)
		(end 332.640686 -268.07541)
		(width 0.088646)
		(layer "In6.Cu")
		(net "M_C_CPU0_SA_DQ<25>")
	)
	(arc
		(start 335.068164 -266.617704)
		(mid 334.785462 -266.69348)
		(end 334.50276 -266.617704)
		(width 0.088646)
		(layer "In6.Cu")
		(net "M_C_CPU0_SA_DQ<25>")
	)
	(arc
		(start 334.50276 -266.617704)
		(mid 334.315562 -266.567527)
		(end 334.128364 -266.617704)
		(width 0.088646)
		(layer "In6.Cu")
		(net "M_C_CPU0_SA_DQ<25>")
	)
	(arc
		(start 337.32216 -266.617704)
		(mid 337.134962 -266.567527)
		(end 336.947764 -266.617704)
		(width 0.088646)
		(layer "In6.Cu")
		(net "M_C_CPU0_SA_DQ<25>")
	)
	(arc
		(start 336.947764 -266.617704)
		(mid 336.665062 -266.69348)
		(end 336.38236 -266.617704)
		(width 0.088646)
		(layer "In6.Cu")
		(net "M_C_CPU0_SA_DQ<25>")
	)
	(arc
		(start 341.081614 -266.617704)
		(mid 340.894416 -266.567527)
		(end 340.707218 -266.617704)
		(width 0.088646)
		(layer "In6.Cu")
		(net "M_C_CPU0_SA_DQ<25>")
	)
	(arc
		(start 338.827364 -266.617704)
		(mid 338.544662 -266.69348)
		(end 338.26196 -266.617704)
		(width 0.088646)
		(layer "In6.Cu")
		(net "M_C_CPU0_SA_DQ<25>")
	)
	(arc
		(start 336.38236 -266.617704)
		(mid 336.195162 -266.567527)
		(end 336.007964 -266.617704)
		(width 0.088646)
		(layer "In6.Cu")
		(net "M_C_CPU0_SA_DQ<25>")
	)
	(arc
		(start 340.141814 -266.617704)
		(mid 339.954616 -266.567527)
		(end 339.767418 -266.617704)
		(width 0.088646)
		(layer "In6.Cu")
		(net "M_C_CPU0_SA_DQ<25>")
	)
	(arc
		(start 342.021414 -266.617704)
		(mid 341.834216 -266.567527)
		(end 341.647018 -266.617704)
		(width 0.088646)
		(layer "In6.Cu")
		(net "M_C_CPU0_SA_DQ<25>")
	)
	(arc
		(start 333.56296 -266.617704)
		(mid 333.375762 -266.567527)
		(end 333.188564 -266.617704)
		(width 0.088646)
		(layer "In6.Cu")
		(net "M_C_CPU0_SA_DQ<25>")
	)
	(arc
		(start 332.718664 -267.43152)
		(mid 332.677734 -267.458553)
		(end 332.640686 -267.490702)
		(width 0.088646)
		(layer "In6.Cu")
		(net "M_C_CPU0_SA_DQ<25>")
	)
	(arc
		(start 341.647018 -266.617704)
		(mid 341.372819 -266.693539)
		(end 341.096346 -266.62634)
		(width 0.088646)
		(layer "In6.Cu")
		(net "M_C_CPU0_SA_DQ<25>")
	)
	(arc
		(start 333.001112 -266.96035)
		(mid 332.92095 -267.232539)
		(end 332.718664 -267.43152)
		(width 0.088646)
		(layer "In6.Cu")
		(net "M_C_CPU0_SA_DQ<25>")
	)
	(arc
		(start 343.075006 -266.296648)
		(mid 342.978385 -266.381402)
		(end 342.871552 -266.452858)
		(width 0.088646)
		(layer "In6.Cu")
		(net "M_C_CPU0_SA_DQ<25>")
	)
	(arc
		(start 335.44256 -266.617704)
		(mid 335.255362 -266.567527)
		(end 335.068164 -266.617704)
		(width 0.088646)
		(layer "In6.Cu")
		(net "M_C_CPU0_SA_DQ<25>")
	)
	(arc
		(start 337.887564 -266.617704)
		(mid 337.604862 -266.69348)
		(end 337.32216 -266.617704)
		(width 0.088646)
		(layer "In6.Cu")
		(net "M_C_CPU0_SA_DQ<25>")
	)
	(arc
		(start 339.20176 -266.617704)
		(mid 339.014562 -266.567527)
		(end 338.827364 -266.617704)
		(width 0.088646)
		(layer "In6.Cu")
		(net "M_C_CPU0_SA_DQ<25>")
	)
	(arc
		(start 340.707218 -266.617704)
		(mid 340.433019 -266.693539)
		(end 340.156546 -266.62634)
		(width 0.088646)
		(layer "In6.Cu")
		(net "M_C_CPU0_SA_DQ<25>")
	)
	(arc
		(start 342.586818 -266.617704)
		(mid 342.312619 -266.693539)
		(end 342.036146 -266.62634)
		(width 0.088646)
		(layer "In6.Cu")
		(net "M_C_CPU0_SA_DQ<25>")
	)
	(arc
		(start 334.128364 -266.617704)
		(mid 333.845662 -266.69348)
		(end 333.56296 -266.617704)
		(width 0.088646)
		(layer "In6.Cu")
		(net "M_C_CPU0_SA_DQ<25>")
	)
	(arc
		(start 333.17434 -266.625832)
		(mid 333.047297 -266.761648)
		(end 333.001112 -266.941808)
		(width 0.088646)
		(layer "In6.Cu")
		(net "M_C_CPU0_SA_DQ<25>")
	)
	(arc
		(start 339.767418 -266.617704)
		(mid 339.490605 -266.693574)
		(end 339.212174 -266.6238)
		(width 0.088646)
		(layer "In6.Cu")
		(net "M_C_CPU0_SA_DQ<25>")
	)
	(arc
		(start 336.007964 -266.617704)
		(mid 335.725262 -266.69348)
		(end 335.44256 -266.617704)
		(width 0.088646)
		(layer "In6.Cu")
		(net "M_C_CPU0_SA_DQ<25>")
	)
	(arc
		(start 338.26196 -266.617704)
		(mid 338.074762 -266.567527)
		(end 337.887564 -266.617704)
		(width 0.088646)
		(layer "In6.Cu")
		(net "M_C_CPU0_SA_DQ<25>")
	)
	(segment
		(start 272.502376 -288.266632)
		(end 271.168114 -288.266632)
		(width 0.20066)
		(layer "F.Cu")
		(net "M_C_CPU0_SA_DQ<24>")
	)
	(segment
		(start 274.152106 -287.84169)
		(end 274.143978 -287.833562)
		(width 0.101854)
		(layer "F.Cu")
		(net "M_C_CPU0_SA_DQ<24>")
	)
	(segment
		(start 278.711914 -288.266632)
		(end 277.342854 -288.266632)
		(width 0.20066)
		(layer "F.Cu")
		(net "M_C_CPU0_SA_DQ<24>")
	)
	(segment
		(start 343.713562 -266.405868)
		(end 343.713816 -266.406122)
		(width 0.20066)
		(layer "F.Cu")
		(net "M_C_CPU0_SA_DQ<24>")
	)
	(segment
		(start 273.37258 -288.043112)
		(end 273.37258 -288.332672)
		(width 0.20066)
		(layer "F.Cu")
		(net "M_C_CPU0_SA_DQ<24>")
	)
	(segment
		(start 273.58213 -287.833562)
		(end 273.37258 -288.043112)
		(width 0.20066)
		(layer "F.Cu")
		(net "M_C_CPU0_SA_DQ<24>")
	)
	(segment
		(start 276.469094 -287.84169)
		(end 274.40001 -287.84169)
		(width 0.1016)
		(layer "F.Cu")
		(net "M_C_CPU0_SA_DQ<24>")
	)
	(segment
		(start 274.143978 -287.833562)
		(end 273.58213 -287.833562)
		(width 0.20066)
		(layer "F.Cu")
		(net "M_C_CPU0_SA_DQ<24>")
	)
	(segment
		(start 279.816814 -288.266632)
		(end 278.711914 -288.266632)
		(width 0.20066)
		(layer "F.Cu")
		(net "M_C_CPU0_SA_DQ<24>")
	)
	(segment
		(start 274.40001 -287.84169)
		(end 274.152106 -287.84169)
		(width 0.101854)
		(layer "F.Cu")
		(net "M_C_CPU0_SA_DQ<24>")
	)
	(segment
		(start 273.37258 -288.332672)
		(end 273.19986 -288.505392)
		(width 0.20066)
		(layer "F.Cu")
		(net "M_C_CPU0_SA_DQ<24>")
	)
	(segment
		(start 273.19986 -288.505392)
		(end 272.741136 -288.505392)
		(width 0.20066)
		(layer "F.Cu")
		(net "M_C_CPU0_SA_DQ<24>")
	)
	(segment
		(start 277.342854 -288.266632)
		(end 276.917912 -287.84169)
		(width 0.20066)
		(layer "F.Cu")
		(net "M_C_CPU0_SA_DQ<24>")
	)
	(segment
		(start 272.741136 -288.505392)
		(end 272.502376 -288.266632)
		(width 0.20066)
		(layer "F.Cu")
		(net "M_C_CPU0_SA_DQ<24>")
	)
	(segment
		(start 343.713816 -266.406122)
		(end 343.713816 -266.941808)
		(width 0.20066)
		(layer "F.Cu")
		(net "M_C_CPU0_SA_DQ<24>")
	)
	(segment
		(start 276.917912 -287.84169)
		(end 276.469094 -287.84169)
		(width 0.20066)
		(layer "F.Cu")
		(net "M_C_CPU0_SA_DQ<24>")
	)
	(segment
		(start 342.116664 -267.43152)
		(end 342.101932 -267.440156)
		(width 0.088646)
		(layer "In6.Cu")
		(net "M_C_CPU0_SA_DQ<24>")
	)
	(segment
		(start 340.237064 -267.43152)
		(end 340.222332 -267.440156)
		(width 0.088646)
		(layer "In6.Cu")
		(net "M_C_CPU0_SA_DQ<24>")
	)
	(segment
		(start 343.42324 -267.340588)
		(end 343.238582 -267.358876)
		(width 0.088646)
		(layer "In6.Cu")
		(net "M_C_CPU0_SA_DQ<24>")
	)
	(segment
		(start 337.802474 -267.437616)
		(end 337.79206 -267.43152)
		(width 0.088646)
		(layer "In6.Cu")
		(net "M_C_CPU0_SA_DQ<24>")
	)
	(segment
		(start 331.283056 -270.12392)
		(end 330.27493 -270.12392)
		(width 0.18288)
		(layer "In6.Cu")
		(net "M_C_CPU0_SA_DQ<24>")
	)
	(segment
		(start 298.478448 -285.291784)
		(end 297.628564 -286.141668)
		(width 0.18288)
		(layer "In6.Cu")
		(net "M_C_CPU0_SA_DQ<24>")
	)
	(segment
		(start 333.471012 -267.755878)
		(end 333.471012 -267.765784)
		(width 0.088646)
		(layer "In6.Cu")
		(net "M_C_CPU0_SA_DQ<24>")
	)
	(segment
		(start 315.057028 -280.027634)
		(end 313.930792 -280.027634)
		(width 0.18288)
		(layer "In6.Cu")
		(net "M_C_CPU0_SA_DQ<24>")
	)
	(segment
		(start 280.241756 -288.691574)
		(end 279.816814 -288.266632)
		(width 0.18288)
		(layer "In6.Cu")
		(net "M_C_CPU0_SA_DQ<24>")
	)
	(segment
		(start 343.08542 -267.41501)
		(end 343.056464 -267.43152)
		(width 0.088646)
		(layer "In6.Cu")
		(net "M_C_CPU0_SA_DQ<24>")
	)
	(segment
		(start 333.658464 -267.43152)
		(end 333.649574 -267.4366)
		(width 0.088646)
		(layer "In6.Cu")
		(net "M_C_CPU0_SA_DQ<24>")
	)
	(segment
		(start 338.742528 -267.437616)
		(end 338.732114 -267.43152)
		(width 0.088646)
		(layer "In6.Cu")
		(net "M_C_CPU0_SA_DQ<24>")
	)
	(segment
		(start 343.15273 -267.382752)
		(end 343.08542 -267.41501)
		(width 0.088646)
		(layer "In6.Cu")
		(net "M_C_CPU0_SA_DQ<24>")
	)
	(segment
		(start 331.73543 -270.12392)
		(end 331.283056 -270.12392)
		(width 0.088646)
		(layer "In6.Cu")
		(net "M_C_CPU0_SA_DQ<24>")
	)
	(segment
		(start 297.628564 -286.141668)
		(end 292.98519 -286.141668)
		(width 0.18288)
		(layer "In6.Cu")
		(net "M_C_CPU0_SA_DQ<24>")
	)
	(segment
		(start 289.124898 -287.552638)
		(end 287.985962 -288.691574)
		(width 0.18288)
		(layer "In6.Cu")
		(net "M_C_CPU0_SA_DQ<24>")
	)
	(segment
		(start 301.456344 -285.291784)
		(end 298.478448 -285.291784)
		(width 0.18288)
		(layer "In6.Cu")
		(net "M_C_CPU0_SA_DQ<24>")
	)
	(segment
		(start 292.98519 -286.141668)
		(end 291.57422 -287.552638)
		(width 0.18288)
		(layer "In6.Cu")
		(net "M_C_CPU0_SA_DQ<24>")
	)
	(segment
		(start 333.110586 -268.304518)
		(end 331.872082 -269.543022)
		(width 0.088646)
		(layer "In6.Cu")
		(net "M_C_CPU0_SA_DQ<24>")
	)
	(segment
		(start 291.57422 -287.552638)
		(end 289.124898 -287.552638)
		(width 0.18288)
		(layer "In6.Cu")
		(net "M_C_CPU0_SA_DQ<24>")
	)
	(segment
		(start 312.891424 -281.067002)
		(end 311.111392 -281.067002)
		(width 0.18288)
		(layer "In6.Cu")
		(net "M_C_CPU0_SA_DQ<24>")
	)
	(segment
		(start 305.7017 -281.893772)
		(end 302.871632 -284.72384)
		(width 0.18288)
		(layer "In6.Cu")
		(net "M_C_CPU0_SA_DQ<24>")
	)
	(segment
		(start 311.111392 -281.067002)
		(end 310.284622 -281.893772)
		(width 0.18288)
		(layer "In6.Cu")
		(net "M_C_CPU0_SA_DQ<24>")
	)
	(segment
		(start 302.024288 -284.72384)
		(end 301.456344 -285.291784)
		(width 0.18288)
		(layer "In6.Cu")
		(net "M_C_CPU0_SA_DQ<24>")
	)
	(segment
		(start 310.284622 -281.893772)
		(end 305.7017 -281.893772)
		(width 0.18288)
		(layer "In6.Cu")
		(net "M_C_CPU0_SA_DQ<24>")
	)
	(segment
		(start 341.176864 -267.43152)
		(end 341.162132 -267.440156)
		(width 0.088646)
		(layer "In6.Cu")
		(net "M_C_CPU0_SA_DQ<24>")
	)
	(segment
		(start 321.206876 -273.877786)
		(end 315.057028 -280.027634)
		(width 0.18288)
		(layer "In6.Cu")
		(net "M_C_CPU0_SA_DQ<24>")
	)
	(segment
		(start 343.056464 -267.43152)
		(end 343.041732 -267.440156)
		(width 0.088646)
		(layer "In6.Cu")
		(net "M_C_CPU0_SA_DQ<24>")
	)
	(segment
		(start 302.871632 -284.72384)
		(end 302.024288 -284.72384)
		(width 0.18288)
		(layer "In6.Cu")
		(net "M_C_CPU0_SA_DQ<24>")
	)
	(segment
		(start 330.27493 -270.12392)
		(end 321.206876 -273.877786)
		(width 0.18288)
		(layer "In6.Cu")
		(net "M_C_CPU0_SA_DQ<24>")
	)
	(segment
		(start 331.872082 -269.987268)
		(end 331.73543 -270.12392)
		(width 0.088646)
		(layer "In6.Cu")
		(net "M_C_CPU0_SA_DQ<24>")
	)
	(segment
		(start 343.511124 -267.309346)
		(end 343.507568 -267.311632)
		(width 0.088646)
		(layer "In6.Cu")
		(net "M_C_CPU0_SA_DQ<24>")
	)
	(segment
		(start 331.872082 -269.543022)
		(end 331.872082 -269.987268)
		(width 0.088646)
		(layer "In6.Cu")
		(net "M_C_CPU0_SA_DQ<24>")
	)
	(segment
		(start 287.985962 -288.691574)
		(end 280.241756 -288.691574)
		(width 0.18288)
		(layer "In6.Cu")
		(net "M_C_CPU0_SA_DQ<24>")
	)
	(segment
		(start 313.930792 -280.027634)
		(end 312.891424 -281.067002)
		(width 0.18288)
		(layer "In6.Cu")
		(net "M_C_CPU0_SA_DQ<24>")
	)
	(arc
		(start 335.538064 -267.43152)
		(mid 335.255362 -267.507262)
		(end 334.97266 -267.43152)
		(width 0.088646)
		(layer "In6.Cu")
		(net "M_C_CPU0_SA_DQ<24>")
	)
	(arc
		(start 343.041732 -267.440156)
		(mid 342.765291 -267.507322)
		(end 342.49106 -267.43152)
		(width 0.088646)
		(layer "In6.Cu")
		(net "M_C_CPU0_SA_DQ<24>")
	)
	(arc
		(start 343.713816 -266.941808)
		(mid 343.659839 -267.151699)
		(end 343.511124 -267.309346)
		(width 0.088646)
		(layer "In6.Cu")
		(net "M_C_CPU0_SA_DQ<24>")
	)
	(arc
		(start 333.188564 -268.245336)
		(mid 333.147634 -268.272369)
		(end 333.110586 -268.304518)
		(width 0.088646)
		(layer "In6.Cu")
		(net "M_C_CPU0_SA_DQ<24>")
	)
	(arc
		(start 336.477864 -267.43152)
		(mid 336.195162 -267.507262)
		(end 335.91246 -267.43152)
		(width 0.088646)
		(layer "In6.Cu")
		(net "M_C_CPU0_SA_DQ<24>")
	)
	(arc
		(start 339.297264 -267.43152)
		(mid 339.020705 -267.507229)
		(end 338.742528 -267.437616)
		(width 0.088646)
		(layer "In6.Cu")
		(net "M_C_CPU0_SA_DQ<24>")
	)
	(arc
		(start 336.85226 -267.43152)
		(mid 336.665062 -267.381377)
		(end 336.477864 -267.43152)
		(width 0.088646)
		(layer "In6.Cu")
		(net "M_C_CPU0_SA_DQ<24>")
	)
	(arc
		(start 338.357718 -267.43152)
		(mid 338.080905 -267.507356)
		(end 337.802474 -267.437616)
		(width 0.088646)
		(layer "In6.Cu")
		(net "M_C_CPU0_SA_DQ<24>")
	)
	(arc
		(start 342.49106 -267.43152)
		(mid 342.303862 -267.381377)
		(end 342.116664 -267.43152)
		(width 0.088646)
		(layer "In6.Cu")
		(net "M_C_CPU0_SA_DQ<24>")
	)
	(arc
		(start 342.101932 -267.440156)
		(mid 341.825491 -267.507322)
		(end 341.55126 -267.43152)
		(width 0.088646)
		(layer "In6.Cu")
		(net "M_C_CPU0_SA_DQ<24>")
	)
	(arc
		(start 334.97266 -267.43152)
		(mid 334.785462 -267.381377)
		(end 334.598264 -267.43152)
		(width 0.088646)
		(layer "In6.Cu")
		(net "M_C_CPU0_SA_DQ<24>")
	)
	(arc
		(start 341.162132 -267.440156)
		(mid 340.885691 -267.507322)
		(end 340.61146 -267.43152)
		(width 0.088646)
		(layer "In6.Cu")
		(net "M_C_CPU0_SA_DQ<24>")
	)
	(arc
		(start 341.55126 -267.43152)
		(mid 341.364062 -267.381377)
		(end 341.176864 -267.43152)
		(width 0.088646)
		(layer "In6.Cu")
		(net "M_C_CPU0_SA_DQ<24>")
	)
	(arc
		(start 333.471012 -267.765784)
		(mid 333.392901 -268.042733)
		(end 333.188564 -268.245336)
		(width 0.088646)
		(layer "In6.Cu")
		(net "M_C_CPU0_SA_DQ<24>")
	)
	(arc
		(start 334.03286 -267.43152)
		(mid 333.845662 -267.381377)
		(end 333.658464 -267.43152)
		(width 0.088646)
		(layer "In6.Cu")
		(net "M_C_CPU0_SA_DQ<24>")
	)
	(arc
		(start 333.649574 -267.4366)
		(mid 333.51866 -267.57296)
		(end 333.471012 -267.755878)
		(width 0.088646)
		(layer "In6.Cu")
		(net "M_C_CPU0_SA_DQ<24>")
	)
	(arc
		(start 340.222332 -267.440156)
		(mid 339.945891 -267.507322)
		(end 339.67166 -267.43152)
		(width 0.088646)
		(layer "In6.Cu")
		(net "M_C_CPU0_SA_DQ<24>")
	)
	(arc
		(start 338.732114 -267.43152)
		(mid 338.544916 -267.381377)
		(end 338.357718 -267.43152)
		(width 0.088646)
		(layer "In6.Cu")
		(net "M_C_CPU0_SA_DQ<24>")
	)
	(arc
		(start 337.417664 -267.43152)
		(mid 337.134962 -267.507262)
		(end 336.85226 -267.43152)
		(width 0.088646)
		(layer "In6.Cu")
		(net "M_C_CPU0_SA_DQ<24>")
	)
	(arc
		(start 337.79206 -267.43152)
		(mid 337.604862 -267.381377)
		(end 337.417664 -267.43152)
		(width 0.088646)
		(layer "In6.Cu")
		(net "M_C_CPU0_SA_DQ<24>")
	)
	(arc
		(start 343.238582 -267.358876)
		(mid 343.194627 -267.367112)
		(end 343.15273 -267.382752)
		(width 0.088646)
		(layer "In6.Cu")
		(net "M_C_CPU0_SA_DQ<24>")
	)
	(arc
		(start 335.91246 -267.43152)
		(mid 335.725262 -267.381377)
		(end 335.538064 -267.43152)
		(width 0.088646)
		(layer "In6.Cu")
		(net "M_C_CPU0_SA_DQ<24>")
	)
	(arc
		(start 343.507568 -267.311632)
		(mid 343.467086 -267.331)
		(end 343.42324 -267.340588)
		(width 0.088646)
		(layer "In6.Cu")
		(net "M_C_CPU0_SA_DQ<24>")
	)
	(arc
		(start 340.61146 -267.43152)
		(mid 340.424262 -267.381377)
		(end 340.237064 -267.43152)
		(width 0.088646)
		(layer "In6.Cu")
		(net "M_C_CPU0_SA_DQ<24>")
	)
	(arc
		(start 339.67166 -267.43152)
		(mid 339.484462 -267.381377)
		(end 339.297264 -267.43152)
		(width 0.088646)
		(layer "In6.Cu")
		(net "M_C_CPU0_SA_DQ<24>")
	)
	(arc
		(start 334.598264 -267.43152)
		(mid 334.315562 -267.507262)
		(end 334.03286 -267.43152)
		(width 0.088646)
		(layer "In6.Cu")
		(net "M_C_CPU0_SA_DQ<24>")
	)
	(segment
		(start 281.99588 -289.11677)
		(end 281.788362 -289.324288)
		(width 0.20066)
		(layer "F.Cu")
		(net "M_C_CPU0_SA_DQ<23>")
	)
	(segment
		(start 277.091394 -289.242754)
		(end 276.96541 -289.11677)
		(width 0.20066)
		(layer "F.Cu")
		(net "M_C_CPU0_SA_DQ<23>")
	)
	(segment
		(start 277.233888 -289.555936)
		(end 277.091394 -289.413442)
		(width 0.20066)
		(layer "F.Cu")
		(net "M_C_CPU0_SA_DQ<23>")
	)
	(segment
		(start 277.601934 -289.541712)
		(end 277.58771 -289.555936)
		(width 0.101854)
		(layer "F.Cu")
		(net "M_C_CPU0_SA_DQ<23>")
	)
	(segment
		(start 277.091394 -289.413442)
		(end 277.091394 -289.242754)
		(width 0.20066)
		(layer "F.Cu")
		(net "M_C_CPU0_SA_DQ<23>")
	)
	(segment
		(start 277.839932 -289.541712)
		(end 277.601934 -289.541712)
		(width 0.101854)
		(layer "F.Cu")
		(net "M_C_CPU0_SA_DQ<23>")
	)
	(segment
		(start 280.606246 -289.240976)
		(end 280.606246 -289.392614)
		(width 0.20066)
		(layer "F.Cu")
		(net "M_C_CPU0_SA_DQ<23>")
	)
	(segment
		(start 282.811982 -289.11677)
		(end 281.99588 -289.11677)
		(width 0.20066)
		(layer "F.Cu")
		(net "M_C_CPU0_SA_DQ<23>")
	)
	(segment
		(start 279.912826 -289.541712)
		(end 277.839932 -289.541712)
		(width 0.1016)
		(layer "F.Cu")
		(net "M_C_CPU0_SA_DQ<23>")
	)
	(segment
		(start 341.364062 -265.592306)
		(end 341.364062 -266.128246)
		(width 0.20066)
		(layer "F.Cu")
		(net "M_C_CPU0_SA_DQ<23>")
	)
	(segment
		(start 280.606246 -289.392614)
		(end 280.457148 -289.541712)
		(width 0.20066)
		(layer "F.Cu")
		(net "M_C_CPU0_SA_DQ<23>")
	)
	(segment
		(start 281.34183 -289.324288)
		(end 281.129994 -289.112452)
		(width 0.20066)
		(layer "F.Cu")
		(net "M_C_CPU0_SA_DQ<23>")
	)
	(segment
		(start 276.96541 -289.11677)
		(end 275.268182 -289.11677)
		(width 0.20066)
		(layer "F.Cu")
		(net "M_C_CPU0_SA_DQ<23>")
	)
	(segment
		(start 280.457148 -289.541712)
		(end 279.912826 -289.541712)
		(width 0.20066)
		(layer "F.Cu")
		(net "M_C_CPU0_SA_DQ<23>")
	)
	(segment
		(start 277.58771 -289.555936)
		(end 277.233888 -289.555936)
		(width 0.20066)
		(layer "F.Cu")
		(net "M_C_CPU0_SA_DQ<23>")
	)
	(segment
		(start 280.73477 -289.112452)
		(end 280.606246 -289.240976)
		(width 0.20066)
		(layer "F.Cu")
		(net "M_C_CPU0_SA_DQ<23>")
	)
	(segment
		(start 281.129994 -289.112452)
		(end 280.73477 -289.112452)
		(width 0.20066)
		(layer "F.Cu")
		(net "M_C_CPU0_SA_DQ<23>")
	)
	(segment
		(start 341.364316 -265.592306)
		(end 341.364062 -265.592306)
		(width 0.20066)
		(layer "F.Cu")
		(net "M_C_CPU0_SA_DQ<23>")
	)
	(segment
		(start 281.788362 -289.324288)
		(end 281.34183 -289.324288)
		(width 0.20066)
		(layer "F.Cu")
		(net "M_C_CPU0_SA_DQ<23>")
	)
	(segment
		(start 283.916882 -289.11677)
		(end 282.811982 -289.11677)
		(width 0.20066)
		(layer "F.Cu")
		(net "M_C_CPU0_SA_DQ<23>")
	)
	(segment
		(start 316.886844 -278.338534)
		(end 315.422026 -281.87523)
		(width 0.18288)
		(layer "In4.Cu")
		(net "M_C_CPU0_SA_DQ<23>")
	)
	(segment
		(start 289.885628 -287.11779)
		(end 289.885628 -287.592516)
		(width 0.18288)
		(layer "In4.Cu")
		(net "M_C_CPU0_SA_DQ<23>")
	)
	(segment
		(start 306.855622 -285.989014)
		(end 306.240688 -285.989014)
		(width 0.18288)
		(layer "In4.Cu")
		(net "M_C_CPU0_SA_DQ<23>")
	)
	(segment
		(start 288.721038 -286.977074)
		(end 288.538158 -286.794194)
		(width 0.18288)
		(layer "In4.Cu")
		(net "M_C_CPU0_SA_DQ<23>")
	)
	(segment
		(start 298.761912 -287.907984)
		(end 298.735242 -287.918906)
		(width 0.18288)
		(layer "In4.Cu")
		(net "M_C_CPU0_SA_DQ<23>")
	)
	(segment
		(start 311.505854 -284.38348)
		(end 310.607964 -285.28137)
		(width 0.18288)
		(layer "In4.Cu")
		(net "M_C_CPU0_SA_DQ<23>")
	)
	(segment
		(start 285.822644 -287.18383)
		(end 285.639764 -287.36671)
		(width 0.18288)
		(layer "In4.Cu")
		(net "M_C_CPU0_SA_DQ<23>")
	)
	(segment
		(start 297.870372 -288.16427)
		(end 297.342814 -288.691828)
		(width 0.18288)
		(layer "In4.Cu")
		(net "M_C_CPU0_SA_DQ<23>")
	)
	(segment
		(start 306.240688 -285.989014)
		(end 304.945542 -287.28416)
		(width 0.18288)
		(layer "In4.Cu")
		(net "M_C_CPU0_SA_DQ<23>")
	)
	(segment
		(start 336.951574 -265.64082)
		(end 336.947764 -265.638788)
		(width 0.088646)
		(layer "In4.Cu")
		(net "M_C_CPU0_SA_DQ<23>")
	)
	(segment
		(start 290.759388 -287.775396)
		(end 290.576508 -287.592516)
		(width 0.18288)
		(layer "In4.Cu")
		(net "M_C_CPU0_SA_DQ<23>")
	)
	(segment
		(start 290.576508 -287.11779)
		(end 290.393628 -286.93491)
		(width 0.18288)
		(layer "In4.Cu")
		(net "M_C_CPU0_SA_DQ<23>")
	)
	(segment
		(start 288.903918 -287.775396)
		(end 288.721038 -287.592516)
		(width 0.18288)
		(layer "In4.Cu")
		(net "M_C_CPU0_SA_DQ<23>")
	)
	(segment
		(start 331.016356 -266.51458)
		(end 330.724256 -266.51458)
		(width 0.088646)
		(layer "In4.Cu")
		(net "M_C_CPU0_SA_DQ<23>")
	)
	(segment
		(start 285.639764 -287.36671)
		(end 285.639764 -288.253678)
		(width 0.18288)
		(layer "In4.Cu")
		(net "M_C_CPU0_SA_DQ<23>")
	)
	(segment
		(start 337.891882 -265.641328)
		(end 337.887564 -265.638788)
		(width 0.088646)
		(layer "In4.Cu")
		(net "M_C_CPU0_SA_DQ<23>")
	)
	(segment
		(start 303.075086 -288.097214)
		(end 299.51172 -288.097214)
		(width 0.18288)
		(layer "In4.Cu")
		(net "M_C_CPU0_SA_DQ<23>")
	)
	(segment
		(start 292.220904 -287.988248)
		(end 292.008052 -287.775396)
		(width 0.18288)
		(layer "In4.Cu")
		(net "M_C_CPU0_SA_DQ<23>")
	)
	(segment
		(start 339.767164 -265.638788)
		(end 339.761322 -265.635232)
		(width 0.088646)
		(layer "In4.Cu")
		(net "M_C_CPU0_SA_DQ<23>")
	)
	(segment
		(start 308.44236 -285.664656)
		(end 307.869082 -286.237934)
		(width 0.18288)
		(layer "In4.Cu")
		(net "M_C_CPU0_SA_DQ<23>")
	)
	(segment
		(start 339.773006 -265.64209)
		(end 339.767164 -265.638788)
		(width 0.088646)
		(layer "In4.Cu")
		(net "M_C_CPU0_SA_DQ<23>")
	)
	(segment
		(start 309.624476 -285.664656)
		(end 308.44236 -285.664656)
		(width 0.18288)
		(layer "In4.Cu")
		(net "M_C_CPU0_SA_DQ<23>")
	)
	(segment
		(start 307.104542 -286.237934)
		(end 306.855622 -285.989014)
		(width 0.18288)
		(layer "In4.Cu")
		(net "M_C_CPU0_SA_DQ<23>")
	)
	(segment
		(start 286.330644 -287.36671)
		(end 286.147764 -287.18383)
		(width 0.18288)
		(layer "In4.Cu")
		(net "M_C_CPU0_SA_DQ<23>")
	)
	(segment
		(start 292.008052 -287.775396)
		(end 290.759388 -287.775396)
		(width 0.18288)
		(layer "In4.Cu")
		(net "M_C_CPU0_SA_DQ<23>")
	)
	(segment
		(start 298.735242 -287.918906)
		(end 298.489878 -288.16427)
		(width 0.18288)
		(layer "In4.Cu")
		(net "M_C_CPU0_SA_DQ<23>")
	)
	(segment
		(start 288.213038 -286.794194)
		(end 288.030158 -286.977074)
		(width 0.18288)
		(layer "In4.Cu")
		(net "M_C_CPU0_SA_DQ<23>")
	)
	(segment
		(start 304.945542 -287.28416)
		(end 303.88814 -287.28416)
		(width 0.18288)
		(layer "In4.Cu")
		(net "M_C_CPU0_SA_DQ<23>")
	)
	(segment
		(start 310.007762 -285.28137)
		(end 309.624476 -285.664656)
		(width 0.18288)
		(layer "In4.Cu")
		(net "M_C_CPU0_SA_DQ<23>")
	)
	(segment
		(start 336.382614 -265.638788)
		(end 336.38236 -265.638534)
		(width 0.088646)
		(layer "In4.Cu")
		(net "M_C_CPU0_SA_DQ<23>")
	)
	(segment
		(start 286.513524 -288.523426)
		(end 286.330644 -288.340546)
		(width 0.18288)
		(layer "In4.Cu")
		(net "M_C_CPU0_SA_DQ<23>")
	)
	(segment
		(start 299.51172 -288.097214)
		(end 299.35297 -287.938464)
		(width 0.18288)
		(layer "In4.Cu")
		(net "M_C_CPU0_SA_DQ<23>")
	)
	(segment
		(start 290.576508 -287.592516)
		(end 290.576508 -287.11779)
		(width 0.18288)
		(layer "In4.Cu")
		(net "M_C_CPU0_SA_DQ<23>")
	)
	(segment
		(start 285.370016 -288.523426)
		(end 284.510226 -288.523426)
		(width 0.18288)
		(layer "In4.Cu")
		(net "M_C_CPU0_SA_DQ<23>")
	)
	(segment
		(start 338.833206 -265.64209)
		(end 338.827364 -265.638788)
		(width 0.088646)
		(layer "In4.Cu")
		(net "M_C_CPU0_SA_DQ<23>")
	)
	(segment
		(start 340.860126 -265.919458)
		(end 340.646004 -265.705336)
		(width 0.088646)
		(layer "In4.Cu")
		(net "M_C_CPU0_SA_DQ<23>")
	)
	(segment
		(start 330.724256 -266.51458)
		(end 328.710798 -266.51458)
		(width 0.18288)
		(layer "In4.Cu")
		(net "M_C_CPU0_SA_DQ<23>")
	)
	(segment
		(start 313.525408 -283.035756)
		(end 312.177684 -284.38348)
		(width 0.18288)
		(layer "In4.Cu")
		(net "M_C_CPU0_SA_DQ<23>")
	)
	(segment
		(start 288.721038 -287.592516)
		(end 288.721038 -286.977074)
		(width 0.18288)
		(layer "In4.Cu")
		(net "M_C_CPU0_SA_DQ<23>")
	)
	(segment
		(start 289.702748 -287.775396)
		(end 288.903918 -287.775396)
		(width 0.18288)
		(layer "In4.Cu")
		(net "M_C_CPU0_SA_DQ<23>")
	)
	(segment
		(start 286.330644 -288.340546)
		(end 286.330644 -287.36671)
		(width 0.18288)
		(layer "In4.Cu")
		(net "M_C_CPU0_SA_DQ<23>")
	)
	(segment
		(start 290.068508 -286.93491)
		(end 289.885628 -287.11779)
		(width 0.18288)
		(layer "In4.Cu")
		(net "M_C_CPU0_SA_DQ<23>")
	)
	(segment
		(start 338.827364 -265.638788)
		(end 338.821522 -265.635232)
		(width 0.088646)
		(layer "In4.Cu")
		(net "M_C_CPU0_SA_DQ<23>")
	)
	(segment
		(start 288.030158 -287.592516)
		(end 287.099248 -288.523426)
		(width 0.18288)
		(layer "In4.Cu")
		(net "M_C_CPU0_SA_DQ<23>")
	)
	(segment
		(start 287.099248 -288.523426)
		(end 286.513524 -288.523426)
		(width 0.18288)
		(layer "In4.Cu")
		(net "M_C_CPU0_SA_DQ<23>")
	)
	(segment
		(start 331.319124 -265.975592)
		(end 331.319124 -266.211812)
		(width 0.088646)
		(layer "In4.Cu")
		(net "M_C_CPU0_SA_DQ<23>")
	)
	(segment
		(start 285.639764 -288.253678)
		(end 285.370016 -288.523426)
		(width 0.18288)
		(layer "In4.Cu")
		(net "M_C_CPU0_SA_DQ<23>")
	)
	(segment
		(start 293.823644 -287.988248)
		(end 292.220904 -287.988248)
		(width 0.18288)
		(layer "In4.Cu")
		(net "M_C_CPU0_SA_DQ<23>")
	)
	(segment
		(start 331.319124 -266.211812)
		(end 331.016356 -266.51458)
		(width 0.088646)
		(layer "In4.Cu")
		(net "M_C_CPU0_SA_DQ<23>")
	)
	(segment
		(start 298.489878 -288.16427)
		(end 297.870372 -288.16427)
		(width 0.18288)
		(layer "In4.Cu")
		(net "M_C_CPU0_SA_DQ<23>")
	)
	(segment
		(start 310.607964 -285.28137)
		(end 310.007762 -285.28137)
		(width 0.18288)
		(layer "In4.Cu")
		(net "M_C_CPU0_SA_DQ<23>")
	)
	(segment
		(start 315.422026 -281.87523)
		(end 314.2615 -283.035756)
		(width 0.18288)
		(layer "In4.Cu")
		(net "M_C_CPU0_SA_DQ<23>")
	)
	(segment
		(start 289.885628 -287.592516)
		(end 289.702748 -287.775396)
		(width 0.18288)
		(layer "In4.Cu")
		(net "M_C_CPU0_SA_DQ<23>")
	)
	(segment
		(start 328.710798 -266.51458)
		(end 316.886844 -278.338534)
		(width 0.18288)
		(layer "In4.Cu")
		(net "M_C_CPU0_SA_DQ<23>")
	)
	(segment
		(start 336.947764 -265.638788)
		(end 336.941922 -265.635232)
		(width 0.088646)
		(layer "In4.Cu")
		(net "M_C_CPU0_SA_DQ<23>")
	)
	(segment
		(start 314.2615 -283.035756)
		(end 313.525408 -283.035756)
		(width 0.18288)
		(layer "In4.Cu")
		(net "M_C_CPU0_SA_DQ<23>")
	)
	(segment
		(start 299.11929 -287.84169)
		(end 298.921678 -287.84169)
		(width 0.18288)
		(layer "In4.Cu")
		(net "M_C_CPU0_SA_DQ<23>")
	)
	(segment
		(start 307.869082 -286.237934)
		(end 307.104542 -286.237934)
		(width 0.18288)
		(layer "In4.Cu")
		(net "M_C_CPU0_SA_DQ<23>")
	)
	(segment
		(start 290.393628 -286.93491)
		(end 290.068508 -286.93491)
		(width 0.18288)
		(layer "In4.Cu")
		(net "M_C_CPU0_SA_DQ<23>")
	)
	(segment
		(start 297.342814 -288.691828)
		(end 294.527224 -288.691828)
		(width 0.18288)
		(layer "In4.Cu")
		(net "M_C_CPU0_SA_DQ<23>")
	)
	(segment
		(start 331.566266 -265.72845)
		(end 331.319124 -265.975592)
		(width 0.088646)
		(layer "In4.Cu")
		(net "M_C_CPU0_SA_DQ<23>")
	)
	(segment
		(start 303.88814 -287.28416)
		(end 303.075086 -288.097214)
		(width 0.18288)
		(layer "In4.Cu")
		(net "M_C_CPU0_SA_DQ<23>")
	)
	(segment
		(start 286.147764 -287.18383)
		(end 285.822644 -287.18383)
		(width 0.18288)
		(layer "In4.Cu")
		(net "M_C_CPU0_SA_DQ<23>")
	)
	(segment
		(start 299.35297 -287.938464)
		(end 299.11929 -287.84169)
		(width 0.18288)
		(layer "In4.Cu")
		(net "M_C_CPU0_SA_DQ<23>")
	)
	(segment
		(start 288.538158 -286.794194)
		(end 288.213038 -286.794194)
		(width 0.18288)
		(layer "In4.Cu")
		(net "M_C_CPU0_SA_DQ<23>")
	)
	(segment
		(start 294.527224 -288.691828)
		(end 293.823644 -287.988248)
		(width 0.18288)
		(layer "In4.Cu")
		(net "M_C_CPU0_SA_DQ<23>")
	)
	(segment
		(start 284.510226 -288.523426)
		(end 283.916882 -289.11677)
		(width 0.18288)
		(layer "In4.Cu")
		(net "M_C_CPU0_SA_DQ<23>")
	)
	(segment
		(start 288.030158 -286.977074)
		(end 288.030158 -287.592516)
		(width 0.18288)
		(layer "In4.Cu")
		(net "M_C_CPU0_SA_DQ<23>")
	)
	(segment
		(start 312.177684 -284.38348)
		(end 311.505854 -284.38348)
		(width 0.18288)
		(layer "In4.Cu")
		(net "M_C_CPU0_SA_DQ<23>")
	)
	(segment
		(start 298.921678 -287.84169)
		(end 298.761912 -287.907984)
		(width 0.18288)
		(layer "In4.Cu")
		(net "M_C_CPU0_SA_DQ<23>")
	)
	(arc
		(start 335.068164 -265.638534)
		(mid 334.785462 -265.562792)
		(end 334.50276 -265.638534)
		(width 0.088646)
		(layer "In4.Cu")
		(net "M_C_CPU0_SA_DQ<23>")
	)
	(arc
		(start 339.202014 -265.638788)
		(mid 339.01806 -265.688883)
		(end 338.833206 -265.64209)
		(width 0.088646)
		(layer "In4.Cu")
		(net "M_C_CPU0_SA_DQ<23>")
	)
	(arc
		(start 335.44256 -265.638534)
		(mid 335.255362 -265.688677)
		(end 335.068164 -265.638534)
		(width 0.088646)
		(layer "In4.Cu")
		(net "M_C_CPU0_SA_DQ<23>")
	)
	(arc
		(start 336.941922 -265.635232)
		(mid 336.661787 -265.562916)
		(end 336.382614 -265.638788)
		(width 0.088646)
		(layer "In4.Cu")
		(net "M_C_CPU0_SA_DQ<23>")
	)
	(arc
		(start 336.38236 -265.638534)
		(mid 336.195162 -265.688677)
		(end 336.007964 -265.638534)
		(width 0.088646)
		(layer "In4.Cu")
		(net "M_C_CPU0_SA_DQ<23>")
	)
	(arc
		(start 333.56296 -265.638534)
		(mid 333.375762 -265.688677)
		(end 333.188564 -265.638534)
		(width 0.088646)
		(layer "In4.Cu")
		(net "M_C_CPU0_SA_DQ<23>")
	)
	(arc
		(start 336.007964 -265.638534)
		(mid 335.725262 -265.562792)
		(end 335.44256 -265.638534)
		(width 0.088646)
		(layer "In4.Cu")
		(net "M_C_CPU0_SA_DQ<23>")
	)
	(arc
		(start 341.364062 -266.128246)
		(mid 341.091314 -266.073993)
		(end 340.860126 -265.919458)
		(width 0.088646)
		(layer "In4.Cu")
		(net "M_C_CPU0_SA_DQ<23>")
	)
	(arc
		(start 340.141814 -265.638788)
		(mid 339.95786 -265.688883)
		(end 339.773006 -265.64209)
		(width 0.088646)
		(layer "In4.Cu")
		(net "M_C_CPU0_SA_DQ<23>")
	)
	(arc
		(start 334.128364 -265.638534)
		(mid 333.845662 -265.562792)
		(end 333.56296 -265.638534)
		(width 0.088646)
		(layer "In4.Cu")
		(net "M_C_CPU0_SA_DQ<23>")
	)
	(arc
		(start 334.50276 -265.638534)
		(mid 334.315562 -265.688677)
		(end 334.128364 -265.638534)
		(width 0.088646)
		(layer "In4.Cu")
		(net "M_C_CPU0_SA_DQ<23>")
	)
	(arc
		(start 332.248764 -265.638534)
		(mid 331.892241 -265.567631)
		(end 331.566266 -265.72845)
		(width 0.088646)
		(layer "In4.Cu")
		(net "M_C_CPU0_SA_DQ<23>")
	)
	(arc
		(start 339.761322 -265.635232)
		(mid 339.481187 -265.562916)
		(end 339.202014 -265.638788)
		(width 0.088646)
		(layer "In4.Cu")
		(net "M_C_CPU0_SA_DQ<23>")
	)
	(arc
		(start 338.821522 -265.635232)
		(mid 338.541387 -265.562916)
		(end 338.262214 -265.638788)
		(width 0.088646)
		(layer "In4.Cu")
		(net "M_C_CPU0_SA_DQ<23>")
	)
	(arc
		(start 333.188564 -265.638534)
		(mid 332.905862 -265.562792)
		(end 332.62316 -265.638534)
		(width 0.088646)
		(layer "In4.Cu")
		(net "M_C_CPU0_SA_DQ<23>")
	)
	(arc
		(start 337.322414 -265.638788)
		(mid 337.137264 -265.688892)
		(end 336.951574 -265.64082)
		(width 0.088646)
		(layer "In4.Cu")
		(net "M_C_CPU0_SA_DQ<23>")
	)
	(arc
		(start 338.262214 -265.638788)
		(mid 338.077377 -265.689015)
		(end 337.891882 -265.641328)
		(width 0.088646)
		(layer "In4.Cu")
		(net "M_C_CPU0_SA_DQ<23>")
	)
	(arc
		(start 332.62316 -265.638534)
		(mid 332.435962 -265.688677)
		(end 332.248764 -265.638534)
		(width 0.088646)
		(layer "In4.Cu")
		(net "M_C_CPU0_SA_DQ<23>")
	)
	(arc
		(start 340.646004 -265.705336)
		(mid 340.40521 -265.586561)
		(end 340.141814 -265.638788)
		(width 0.088646)
		(layer "In4.Cu")
		(net "M_C_CPU0_SA_DQ<23>")
	)
	(arc
		(start 337.887564 -265.638788)
		(mid 337.605006 -265.563139)
		(end 337.322414 -265.638788)
		(width 0.088646)
		(layer "In4.Cu")
		(net "M_C_CPU0_SA_DQ<23>")
	)
	(segment
		(start 280.689558 -290.535614)
		(end 280.545794 -290.39185)
		(width 0.20066)
		(layer "F.Cu")
		(net "M_C_CPU0_SA_DQ<22>")
	)
	(segment
		(start 281.285442 -291.028628)
		(end 280.856944 -291.028628)
		(width 0.20066)
		(layer "F.Cu")
		(net "M_C_CPU0_SA_DQ<22>")
	)
	(segment
		(start 277.59787 -290.39185)
		(end 277.58771 -290.38169)
		(width 0.101854)
		(layer "F.Cu")
		(net "M_C_CPU0_SA_DQ<22>")
	)
	(segment
		(start 280.689558 -290.861242)
		(end 280.689558 -290.535614)
		(width 0.20066)
		(layer "F.Cu")
		(net "M_C_CPU0_SA_DQ<22>")
	)
	(segment
		(start 283.916882 -290.816792)
		(end 282.811982 -290.816792)
		(width 0.20066)
		(layer "F.Cu")
		(net "M_C_CPU0_SA_DQ<22>")
	)
	(segment
		(start 276.850348 -290.38169)
		(end 276.415246 -290.816792)
		(width 0.20066)
		(layer "F.Cu")
		(net "M_C_CPU0_SA_DQ<22>")
	)
	(segment
		(start 282.811982 -290.816792)
		(end 281.497278 -290.816792)
		(width 0.20066)
		(layer "F.Cu")
		(net "M_C_CPU0_SA_DQ<22>")
	)
	(segment
		(start 341.834216 -266.406122)
		(end 341.834216 -266.941808)
		(width 0.20066)
		(layer "F.Cu")
		(net "M_C_CPU0_SA_DQ<22>")
	)
	(segment
		(start 281.497278 -290.816792)
		(end 281.285442 -291.028628)
		(width 0.20066)
		(layer "F.Cu")
		(net "M_C_CPU0_SA_DQ<22>")
	)
	(segment
		(start 277.58771 -290.38169)
		(end 276.850348 -290.38169)
		(width 0.20066)
		(layer "F.Cu")
		(net "M_C_CPU0_SA_DQ<22>")
	)
	(segment
		(start 280.856944 -291.028628)
		(end 280.689558 -290.861242)
		(width 0.20066)
		(layer "F.Cu")
		(net "M_C_CPU0_SA_DQ<22>")
	)
	(segment
		(start 280.545794 -290.39185)
		(end 279.912826 -290.39185)
		(width 0.20066)
		(layer "F.Cu")
		(net "M_C_CPU0_SA_DQ<22>")
	)
	(segment
		(start 277.852886 -290.39185)
		(end 277.59787 -290.39185)
		(width 0.101854)
		(layer "F.Cu")
		(net "M_C_CPU0_SA_DQ<22>")
	)
	(segment
		(start 276.415246 -290.816792)
		(end 275.268182 -290.816792)
		(width 0.20066)
		(layer "F.Cu")
		(net "M_C_CPU0_SA_DQ<22>")
	)
	(segment
		(start 279.912826 -290.39185)
		(end 277.852886 -290.39185)
		(width 0.1016)
		(layer "F.Cu")
		(net "M_C_CPU0_SA_DQ<22>")
	)
	(segment
		(start 341.833962 -266.405868)
		(end 341.834216 -266.406122)
		(width 0.20066)
		(layer "F.Cu")
		(net "M_C_CPU0_SA_DQ<22>")
	)
	(segment
		(start 291.856668 -289.342068)
		(end 290.80587 -289.342068)
		(width 0.18288)
		(layer "In4.Cu")
		(net "M_C_CPU0_SA_DQ<22>")
	)
	(segment
		(start 311.408826 -286.060642)
		(end 310.565038 -286.90443)
		(width 0.18288)
		(layer "In4.Cu")
		(net "M_C_CPU0_SA_DQ<22>")
	)
	(segment
		(start 305.87061 -288.098738)
		(end 305.87061 -289.06851)
		(width 0.18288)
		(layer "In4.Cu")
		(net "M_C_CPU0_SA_DQ<22>")
	)
	(segment
		(start 312.113676 -286.060642)
		(end 311.408826 -286.060642)
		(width 0.18288)
		(layer "In4.Cu")
		(net "M_C_CPU0_SA_DQ<22>")
	)
	(segment
		(start 307.794914 -287.85566)
		(end 307.220366 -287.85566)
		(width 0.18288)
		(layer "In4.Cu")
		(net "M_C_CPU0_SA_DQ<22>")
	)
	(segment
		(start 289.93211 -289.524948)
		(end 289.74923 -289.342068)
		(width 0.18288)
		(layer "In4.Cu")
		(net "M_C_CPU0_SA_DQ<22>")
	)
	(segment
		(start 287.634934 -290.149026)
		(end 286.666178 -290.149026)
		(width 0.18288)
		(layer "In4.Cu")
		(net "M_C_CPU0_SA_DQ<22>")
	)
	(segment
		(start 301.07255 -289.863022)
		(end 300.75124 -289.541712)
		(width 0.18288)
		(layer "In4.Cu")
		(net "M_C_CPU0_SA_DQ<22>")
	)
	(segment
		(start 301.861728 -289.541712)
		(end 301.540418 -289.863022)
		(width 0.18288)
		(layer "In4.Cu")
		(net "M_C_CPU0_SA_DQ<22>")
	)
	(segment
		(start 288.964116 -289.342068)
		(end 288.775902 -289.530282)
		(width 0.18288)
		(layer "In4.Cu")
		(net "M_C_CPU0_SA_DQ<22>")
	)
	(segment
		(start 288.775902 -289.530282)
		(end 288.775902 -290.171378)
		(width 0.18288)
		(layer "In4.Cu")
		(net "M_C_CPU0_SA_DQ<22>")
	)
	(segment
		(start 303.803558 -290.509706)
		(end 302.835564 -289.541712)
		(width 0.18288)
		(layer "In4.Cu")
		(net "M_C_CPU0_SA_DQ<22>")
	)
	(segment
		(start 339.671914 -266.452604)
		(end 339.666072 -266.455906)
		(width 0.088646)
		(layer "In4.Cu")
		(net "M_C_CPU0_SA_DQ<22>")
	)
	(segment
		(start 294.442642 -290.39185)
		(end 293.553388 -289.502596)
		(width 0.18288)
		(layer "In4.Cu")
		(net "M_C_CPU0_SA_DQ<22>")
	)
	(segment
		(start 310.565038 -286.90443)
		(end 308.746144 -286.90443)
		(width 0.18288)
		(layer "In4.Cu")
		(net "M_C_CPU0_SA_DQ<22>")
	)
	(segment
		(start 340.611714 -266.452604)
		(end 340.605872 -266.455906)
		(width 0.088646)
		(layer "In4.Cu")
		(net "M_C_CPU0_SA_DQ<22>")
	)
	(segment
		(start 336.856324 -266.450318)
		(end 336.85226 -266.45235)
		(width 0.088646)
		(layer "In4.Cu")
		(net "M_C_CPU0_SA_DQ<22>")
	)
	(segment
		(start 293.120572 -289.502596)
		(end 292.966394 -289.656774)
		(width 0.18288)
		(layer "In4.Cu")
		(net "M_C_CPU0_SA_DQ<22>")
	)
	(segment
		(start 339.677756 -266.449048)
		(end 339.671914 -266.452604)
		(width 0.088646)
		(layer "In4.Cu")
		(net "M_C_CPU0_SA_DQ<22>")
	)
	(segment
		(start 290.80587 -289.342068)
		(end 290.62299 -289.524948)
		(width 0.18288)
		(layer "In4.Cu")
		(net "M_C_CPU0_SA_DQ<22>")
	)
	(segment
		(start 340.617556 -266.449048)
		(end 340.611714 -266.452604)
		(width 0.088646)
		(layer "In4.Cu")
		(net "M_C_CPU0_SA_DQ<22>")
	)
	(segment
		(start 305.87061 -289.06851)
		(end 304.429414 -290.509706)
		(width 0.18288)
		(layer "In4.Cu")
		(net "M_C_CPU0_SA_DQ<22>")
	)
	(segment
		(start 338.737956 -266.449048)
		(end 338.73186 -266.45235)
		(width 0.088646)
		(layer "In4.Cu")
		(net "M_C_CPU0_SA_DQ<22>")
	)
	(segment
		(start 287.966658 -290.48075)
		(end 287.634934 -290.149026)
		(width 0.18288)
		(layer "In4.Cu")
		(net "M_C_CPU0_SA_DQ<22>")
	)
	(segment
		(start 306.998878 -287.634172)
		(end 306.335176 -287.634172)
		(width 0.18288)
		(layer "In4.Cu")
		(net "M_C_CPU0_SA_DQ<22>")
	)
	(segment
		(start 308.746144 -286.90443)
		(end 307.794914 -287.85566)
		(width 0.18288)
		(layer "In4.Cu")
		(net "M_C_CPU0_SA_DQ<22>")
	)
	(segment
		(start 317.921894 -278.779224)
		(end 316.336172 -282.607258)
		(width 0.18288)
		(layer "In4.Cu")
		(net "M_C_CPU0_SA_DQ<22>")
	)
	(segment
		(start 284.584648 -290.149026)
		(end 283.916882 -290.816792)
		(width 0.18288)
		(layer "In4.Cu")
		(net "M_C_CPU0_SA_DQ<22>")
	)
	(segment
		(start 297.405044 -290.39185)
		(end 294.442642 -290.39185)
		(width 0.18288)
		(layer "In4.Cu")
		(net "M_C_CPU0_SA_DQ<22>")
	)
	(segment
		(start 329.190858 -267.51026)
		(end 317.921894 -278.779224)
		(width 0.18288)
		(layer "In4.Cu")
		(net "M_C_CPU0_SA_DQ<22>")
	)
	(segment
		(start 285.792418 -290.331906)
		(end 285.609538 -290.149026)
		(width 0.18288)
		(layer "In4.Cu")
		(net "M_C_CPU0_SA_DQ<22>")
	)
	(segment
		(start 286.300418 -290.735258)
		(end 285.975298 -290.735258)
		(width 0.18288)
		(layer "In4.Cu")
		(net "M_C_CPU0_SA_DQ<22>")
	)
	(segment
		(start 301.540418 -289.863022)
		(end 301.07255 -289.863022)
		(width 0.18288)
		(layer "In4.Cu")
		(net "M_C_CPU0_SA_DQ<22>")
	)
	(segment
		(start 300.75124 -289.541712)
		(end 298.255182 -289.541712)
		(width 0.18288)
		(layer "In4.Cu")
		(net "M_C_CPU0_SA_DQ<22>")
	)
	(segment
		(start 291.862002 -289.336734)
		(end 291.856668 -289.342068)
		(width 0.18288)
		(layer "In4.Cu")
		(net "M_C_CPU0_SA_DQ<22>")
	)
	(segment
		(start 337.417664 -266.45235)
		(end 337.417664 -266.452604)
		(width 0.088646)
		(layer "In4.Cu")
		(net "M_C_CPU0_SA_DQ<22>")
	)
	(segment
		(start 314.66536 -284.27807)
		(end 313.896248 -284.27807)
		(width 0.18288)
		(layer "In4.Cu")
		(net "M_C_CPU0_SA_DQ<22>")
	)
	(segment
		(start 341.251032 -266.495276)
		(end 341.176864 -266.452604)
		(width 0.088646)
		(layer "In4.Cu")
		(net "M_C_CPU0_SA_DQ<22>")
	)
	(segment
		(start 330.724256 -267.51026)
		(end 329.190858 -267.51026)
		(width 0.18288)
		(layer "In4.Cu")
		(net "M_C_CPU0_SA_DQ<22>")
	)
	(segment
		(start 285.609538 -290.149026)
		(end 284.584648 -290.149026)
		(width 0.18288)
		(layer "In4.Cu")
		(net "M_C_CPU0_SA_DQ<22>")
	)
	(segment
		(start 316.336172 -282.607258)
		(end 314.66536 -284.27807)
		(width 0.18288)
		(layer "In4.Cu")
		(net "M_C_CPU0_SA_DQ<22>")
	)
	(segment
		(start 292.966394 -289.656774)
		(end 292.182042 -289.656774)
		(width 0.18288)
		(layer "In4.Cu")
		(net "M_C_CPU0_SA_DQ<22>")
	)
	(segment
		(start 285.975298 -290.735258)
		(end 285.792418 -290.552378)
		(width 0.18288)
		(layer "In4.Cu")
		(net "M_C_CPU0_SA_DQ<22>")
	)
	(segment
		(start 298.255182 -289.541712)
		(end 297.405044 -290.39185)
		(width 0.18288)
		(layer "In4.Cu")
		(net "M_C_CPU0_SA_DQ<22>")
	)
	(segment
		(start 286.666178 -290.149026)
		(end 286.483298 -290.331906)
		(width 0.18288)
		(layer "In4.Cu")
		(net "M_C_CPU0_SA_DQ<22>")
	)
	(segment
		(start 290.62299 -289.524948)
		(end 290.62299 -290.135564)
		(width 0.18288)
		(layer "In4.Cu")
		(net "M_C_CPU0_SA_DQ<22>")
	)
	(segment
		(start 286.483298 -290.552378)
		(end 286.300418 -290.735258)
		(width 0.18288)
		(layer "In4.Cu")
		(net "M_C_CPU0_SA_DQ<22>")
	)
	(segment
		(start 290.11499 -290.318444)
		(end 289.93211 -290.135564)
		(width 0.18288)
		(layer "In4.Cu")
		(net "M_C_CPU0_SA_DQ<22>")
	)
	(segment
		(start 302.835564 -289.541712)
		(end 301.861728 -289.541712)
		(width 0.18288)
		(layer "In4.Cu")
		(net "M_C_CPU0_SA_DQ<22>")
	)
	(segment
		(start 286.483298 -290.331906)
		(end 286.483298 -290.552378)
		(width 0.18288)
		(layer "In4.Cu")
		(net "M_C_CPU0_SA_DQ<22>")
	)
	(segment
		(start 289.74923 -289.342068)
		(end 288.964116 -289.342068)
		(width 0.18288)
		(layer "In4.Cu")
		(net "M_C_CPU0_SA_DQ<22>")
	)
	(segment
		(start 331.067918 -267.51026)
		(end 330.724256 -267.51026)
		(width 0.088646)
		(layer "In4.Cu")
		(net "M_C_CPU0_SA_DQ<22>")
	)
	(segment
		(start 288.46653 -290.48075)
		(end 287.966658 -290.48075)
		(width 0.18288)
		(layer "In4.Cu")
		(net "M_C_CPU0_SA_DQ<22>")
	)
	(segment
		(start 332.036166 -266.542012)
		(end 331.067918 -267.51026)
		(width 0.088646)
		(layer "In4.Cu")
		(net "M_C_CPU0_SA_DQ<22>")
	)
	(segment
		(start 290.62299 -290.135564)
		(end 290.44011 -290.318444)
		(width 0.18288)
		(layer "In4.Cu")
		(net "M_C_CPU0_SA_DQ<22>")
	)
	(segment
		(start 285.792418 -290.552378)
		(end 285.792418 -290.331906)
		(width 0.18288)
		(layer "In4.Cu")
		(net "M_C_CPU0_SA_DQ<22>")
	)
	(segment
		(start 289.93211 -290.135564)
		(end 289.93211 -289.524948)
		(width 0.18288)
		(layer "In4.Cu")
		(net "M_C_CPU0_SA_DQ<22>")
	)
	(segment
		(start 288.775902 -290.171378)
		(end 288.46653 -290.48075)
		(width 0.18288)
		(layer "In4.Cu")
		(net "M_C_CPU0_SA_DQ<22>")
	)
	(segment
		(start 307.220366 -287.85566)
		(end 306.998878 -287.634172)
		(width 0.18288)
		(layer "In4.Cu")
		(net "M_C_CPU0_SA_DQ<22>")
	)
	(segment
		(start 292.182042 -289.656774)
		(end 291.862002 -289.336734)
		(width 0.18288)
		(layer "In4.Cu")
		(net "M_C_CPU0_SA_DQ<22>")
	)
	(segment
		(start 293.553388 -289.502596)
		(end 293.120572 -289.502596)
		(width 0.18288)
		(layer "In4.Cu")
		(net "M_C_CPU0_SA_DQ<22>")
	)
	(segment
		(start 290.44011 -290.318444)
		(end 290.11499 -290.318444)
		(width 0.18288)
		(layer "In4.Cu")
		(net "M_C_CPU0_SA_DQ<22>")
	)
	(segment
		(start 304.429414 -290.509706)
		(end 303.803558 -290.509706)
		(width 0.18288)
		(layer "In4.Cu")
		(net "M_C_CPU0_SA_DQ<22>")
	)
	(segment
		(start 306.335176 -287.634172)
		(end 305.87061 -288.098738)
		(width 0.18288)
		(layer "In4.Cu")
		(net "M_C_CPU0_SA_DQ<22>")
	)
	(segment
		(start 313.896248 -284.27807)
		(end 312.113676 -286.060642)
		(width 0.18288)
		(layer "In4.Cu")
		(net "M_C_CPU0_SA_DQ<22>")
	)
	(arc
		(start 341.834216 -266.941808)
		(mid 341.557356 -266.699303)
		(end 341.251032 -266.495276)
		(width 0.088646)
		(layer "In4.Cu")
		(net "M_C_CPU0_SA_DQ<22>")
	)
	(arc
		(start 337.417664 -266.452604)
		(mid 337.137293 -266.376799)
		(end 336.856324 -266.450318)
		(width 0.088646)
		(layer "In4.Cu")
		(net "M_C_CPU0_SA_DQ<22>")
	)
	(arc
		(start 339.297264 -266.452604)
		(mid 339.01809 -266.376805)
		(end 338.737956 -266.449048)
		(width 0.088646)
		(layer "In4.Cu")
		(net "M_C_CPU0_SA_DQ<22>")
	)
	(arc
		(start 334.97266 -266.45235)
		(mid 334.785462 -266.502527)
		(end 334.598264 -266.45235)
		(width 0.088646)
		(layer "In4.Cu")
		(net "M_C_CPU0_SA_DQ<22>")
	)
	(arc
		(start 338.357464 -266.45235)
		(mid 338.074762 -266.376574)
		(end 337.79206 -266.45235)
		(width 0.088646)
		(layer "In4.Cu")
		(net "M_C_CPU0_SA_DQ<22>")
	)
	(arc
		(start 333.09306 -266.45235)
		(mid 332.905862 -266.502527)
		(end 332.718664 -266.45235)
		(width 0.088646)
		(layer "In4.Cu")
		(net "M_C_CPU0_SA_DQ<22>")
	)
	(arc
		(start 335.538064 -266.45235)
		(mid 335.255362 -266.376574)
		(end 334.97266 -266.45235)
		(width 0.088646)
		(layer "In4.Cu")
		(net "M_C_CPU0_SA_DQ<22>")
	)
	(arc
		(start 336.85226 -266.45235)
		(mid 336.665062 -266.502527)
		(end 336.477864 -266.45235)
		(width 0.088646)
		(layer "In4.Cu")
		(net "M_C_CPU0_SA_DQ<22>")
	)
	(arc
		(start 337.79206 -266.45235)
		(mid 337.604862 -266.502527)
		(end 337.417664 -266.45235)
		(width 0.088646)
		(layer "In4.Cu")
		(net "M_C_CPU0_SA_DQ<22>")
	)
	(arc
		(start 340.605872 -266.455906)
		(mid 340.421017 -266.502856)
		(end 340.237064 -266.452604)
		(width 0.088646)
		(layer "In4.Cu")
		(net "M_C_CPU0_SA_DQ<22>")
	)
	(arc
		(start 335.91246 -266.45235)
		(mid 335.725262 -266.502527)
		(end 335.538064 -266.45235)
		(width 0.088646)
		(layer "In4.Cu")
		(net "M_C_CPU0_SA_DQ<22>")
	)
	(arc
		(start 334.598264 -266.45235)
		(mid 334.315562 -266.376574)
		(end 334.03286 -266.45235)
		(width 0.088646)
		(layer "In4.Cu")
		(net "M_C_CPU0_SA_DQ<22>")
	)
	(arc
		(start 338.73186 -266.45235)
		(mid 338.544662 -266.502527)
		(end 338.357464 -266.45235)
		(width 0.088646)
		(layer "In4.Cu")
		(net "M_C_CPU0_SA_DQ<22>")
	)
	(arc
		(start 332.15326 -266.45235)
		(mid 332.091782 -266.493352)
		(end 332.036166 -266.542012)
		(width 0.088646)
		(layer "In4.Cu")
		(net "M_C_CPU0_SA_DQ<22>")
	)
	(arc
		(start 339.666072 -266.455906)
		(mid 339.481217 -266.502856)
		(end 339.297264 -266.452604)
		(width 0.088646)
		(layer "In4.Cu")
		(net "M_C_CPU0_SA_DQ<22>")
	)
	(arc
		(start 332.718664 -266.45235)
		(mid 332.435962 -266.376574)
		(end 332.15326 -266.45235)
		(width 0.088646)
		(layer "In4.Cu")
		(net "M_C_CPU0_SA_DQ<22>")
	)
	(arc
		(start 334.03286 -266.45235)
		(mid 333.845662 -266.502527)
		(end 333.658464 -266.45235)
		(width 0.088646)
		(layer "In4.Cu")
		(net "M_C_CPU0_SA_DQ<22>")
	)
	(arc
		(start 333.658464 -266.45235)
		(mid 333.375762 -266.376574)
		(end 333.09306 -266.45235)
		(width 0.088646)
		(layer "In4.Cu")
		(net "M_C_CPU0_SA_DQ<22>")
	)
	(arc
		(start 341.176864 -266.452604)
		(mid 340.89769 -266.376805)
		(end 340.617556 -266.449048)
		(width 0.088646)
		(layer "In4.Cu")
		(net "M_C_CPU0_SA_DQ<22>")
	)
	(arc
		(start 336.477864 -266.45235)
		(mid 336.195162 -266.376574)
		(end 335.91246 -266.45235)
		(width 0.088646)
		(layer "In4.Cu")
		(net "M_C_CPU0_SA_DQ<22>")
	)
	(arc
		(start 340.237064 -266.452604)
		(mid 339.95789 -266.376805)
		(end 339.677756 -266.449048)
		(width 0.088646)
		(layer "In4.Cu")
		(net "M_C_CPU0_SA_DQ<22>")
	)
	(segment
		(start 273.37258 -290.02355)
		(end 273.218148 -290.177982)
		(width 0.20066)
		(layer "F.Cu")
		(net "M_C_CPU0_SA_DQ<21>")
	)
	(segment
		(start 279.816814 -289.966654)
		(end 278.711914 -289.966654)
		(width 0.20066)
		(layer "F.Cu")
		(net "M_C_CPU0_SA_DQ<21>")
	)
	(segment
		(start 274.152868 -289.541712)
		(end 274.143978 -289.532822)
		(width 0.1016)
		(layer "F.Cu")
		(net "M_C_CPU0_SA_DQ<21>")
	)
	(segment
		(start 277.072598 -289.966654)
		(end 276.647656 -289.541712)
		(width 0.20066)
		(layer "F.Cu")
		(net "M_C_CPU0_SA_DQ<21>")
	)
	(segment
		(start 272.502376 -289.966654)
		(end 271.168114 -289.966654)
		(width 0.20066)
		(layer "F.Cu")
		(net "M_C_CPU0_SA_DQ<21>")
	)
	(segment
		(start 274.143978 -289.532822)
		(end 273.53514 -289.532822)
		(width 0.20066)
		(layer "F.Cu")
		(net "M_C_CPU0_SA_DQ<21>")
	)
	(segment
		(start 273.218148 -290.177982)
		(end 272.713704 -290.177982)
		(width 0.20066)
		(layer "F.Cu")
		(net "M_C_CPU0_SA_DQ<21>")
	)
	(segment
		(start 272.713704 -290.177982)
		(end 272.502376 -289.966654)
		(width 0.20066)
		(layer "F.Cu")
		(net "M_C_CPU0_SA_DQ<21>")
	)
	(segment
		(start 276.647656 -289.541712)
		(end 276.469094 -289.541712)
		(width 0.20066)
		(layer "F.Cu")
		(net "M_C_CPU0_SA_DQ<21>")
	)
	(segment
		(start 340.424516 -265.592306)
		(end 340.424262 -265.592306)
		(width 0.20066)
		(layer "F.Cu")
		(net "M_C_CPU0_SA_DQ<21>")
	)
	(segment
		(start 276.138386 -289.541712)
		(end 274.152868 -289.541712)
		(width 0.1016)
		(layer "F.Cu")
		(net "M_C_CPU0_SA_DQ<21>")
	)
	(segment
		(start 273.37258 -289.695382)
		(end 273.37258 -290.02355)
		(width 0.20066)
		(layer "F.Cu")
		(net "M_C_CPU0_SA_DQ<21>")
	)
	(segment
		(start 273.53514 -289.532822)
		(end 273.37258 -289.695382)
		(width 0.20066)
		(layer "F.Cu")
		(net "M_C_CPU0_SA_DQ<21>")
	)
	(segment
		(start 278.711914 -289.966654)
		(end 277.072598 -289.966654)
		(width 0.20066)
		(layer "F.Cu")
		(net "M_C_CPU0_SA_DQ<21>")
	)
	(segment
		(start 276.469094 -289.541712)
		(end 276.138386 -289.541712)
		(width 0.101854)
		(layer "F.Cu")
		(net "M_C_CPU0_SA_DQ<21>")
	)
	(segment
		(start 340.424262 -265.592306)
		(end 340.424262 -266.128246)
		(width 0.20066)
		(layer "F.Cu")
		(net "M_C_CPU0_SA_DQ<21>")
	)
	(segment
		(start 328.965814 -267.01242)
		(end 317.44158 -278.536654)
		(width 0.18288)
		(layer "In4.Cu")
		(net "M_C_CPU0_SA_DQ<21>")
	)
	(segment
		(start 315.938662 -282.164028)
		(end 314.414408 -283.688282)
		(width 0.18288)
		(layer "In4.Cu")
		(net "M_C_CPU0_SA_DQ<21>")
	)
	(segment
		(start 339.67928 -265.807952)
		(end 339.666072 -265.800332)
		(width 0.088646)
		(layer "In4.Cu")
		(net "M_C_CPU0_SA_DQ<21>")
	)
	(segment
		(start 305.336702 -288.40303)
		(end 304.347118 -289.392614)
		(width 0.18288)
		(layer "In4.Cu")
		(net "M_C_CPU0_SA_DQ<21>")
	)
	(segment
		(start 307.157374 -286.904938)
		(end 306.957476 -287.104836)
		(width 0.18288)
		(layer "In4.Cu")
		(net "M_C_CPU0_SA_DQ<21>")
	)
	(segment
		(start 330.985114 -267.01242)
		(end 330.724256 -267.01242)
		(width 0.088646)
		(layer "In4.Cu")
		(net "M_C_CPU0_SA_DQ<21>")
	)
	(segment
		(start 288.539174 -288.833306)
		(end 287.830768 -289.541712)
		(width 0.18288)
		(layer "In4.Cu")
		(net "M_C_CPU0_SA_DQ<21>")
	)
	(segment
		(start 331.553058 -266.444476)
		(end 330.985114 -267.01242)
		(width 0.088646)
		(layer "In4.Cu")
		(net "M_C_CPU0_SA_DQ<21>")
	)
	(segment
		(start 306.100988 -287.104836)
		(end 305.336702 -287.869122)
		(width 0.18288)
		(layer "In4.Cu")
		(net "M_C_CPU0_SA_DQ<21>")
	)
	(segment
		(start 292.057582 -288.833306)
		(end 288.539174 -288.833306)
		(width 0.18288)
		(layer "In4.Cu")
		(net "M_C_CPU0_SA_DQ<21>")
	)
	(segment
		(start 282.673298 -288.807398)
		(end 282.348178 -288.807398)
		(width 0.18288)
		(layer "In4.Cu")
		(net "M_C_CPU0_SA_DQ<21>")
	)
	(segment
		(start 282.856178 -289.358832)
		(end 282.856178 -288.990278)
		(width 0.18288)
		(layer "In4.Cu")
		(net "M_C_CPU0_SA_DQ<21>")
	)
	(segment
		(start 283.039058 -289.541712)
		(end 282.856178 -289.358832)
		(width 0.18288)
		(layer "In4.Cu")
		(net "M_C_CPU0_SA_DQ<21>")
	)
	(segment
		(start 298.192952 -288.691828)
		(end 297.342814 -289.541966)
		(width 0.18288)
		(layer "In4.Cu")
		(net "M_C_CPU0_SA_DQ<21>")
	)
	(segment
		(start 311.328308 -285.378652)
		(end 310.301894 -286.405066)
		(width 0.18288)
		(layer "In4.Cu")
		(net "M_C_CPU0_SA_DQ<21>")
	)
	(segment
		(start 302.975518 -288.691828)
		(end 298.192952 -288.691828)
		(width 0.18288)
		(layer "In4.Cu")
		(net "M_C_CPU0_SA_DQ<21>")
	)
	(segment
		(start 307.955442 -286.904938)
		(end 307.157374 -286.904938)
		(width 0.18288)
		(layer "In4.Cu")
		(net "M_C_CPU0_SA_DQ<21>")
	)
	(segment
		(start 293.328598 -288.512504)
		(end 292.378384 -288.512504)
		(width 0.18288)
		(layer "In4.Cu")
		(net "M_C_CPU0_SA_DQ<21>")
	)
	(segment
		(start 330.724256 -267.01242)
		(end 328.965814 -267.01242)
		(width 0.18288)
		(layer "In4.Cu")
		(net "M_C_CPU0_SA_DQ<21>")
	)
	(segment
		(start 304.347118 -289.392614)
		(end 303.676304 -289.392614)
		(width 0.18288)
		(layer "In4.Cu")
		(net "M_C_CPU0_SA_DQ<21>")
	)
	(segment
		(start 314.414408 -283.688282)
		(end 313.600592 -283.688282)
		(width 0.18288)
		(layer "In4.Cu")
		(net "M_C_CPU0_SA_DQ<21>")
	)
	(segment
		(start 292.378384 -288.512504)
		(end 292.057582 -288.833306)
		(width 0.18288)
		(layer "In4.Cu")
		(net "M_C_CPU0_SA_DQ<21>")
	)
	(segment
		(start 306.957476 -287.104836)
		(end 306.100988 -287.104836)
		(width 0.18288)
		(layer "In4.Cu")
		(net "M_C_CPU0_SA_DQ<21>")
	)
	(segment
		(start 282.856178 -288.990278)
		(end 282.673298 -288.807398)
		(width 0.18288)
		(layer "In4.Cu")
		(net "M_C_CPU0_SA_DQ<21>")
	)
	(segment
		(start 305.336702 -287.869122)
		(end 305.336702 -288.40303)
		(width 0.18288)
		(layer "In4.Cu")
		(net "M_C_CPU0_SA_DQ<21>")
	)
	(segment
		(start 338.732114 -265.803634)
		(end 338.726272 -265.800332)
		(width 0.088646)
		(layer "In4.Cu")
		(net "M_C_CPU0_SA_DQ<21>")
	)
	(segment
		(start 331.553058 -266.010898)
		(end 331.553058 -266.444476)
		(width 0.088646)
		(layer "In4.Cu")
		(net "M_C_CPU0_SA_DQ<21>")
	)
	(segment
		(start 303.676304 -289.392614)
		(end 302.975518 -288.691828)
		(width 0.18288)
		(layer "In4.Cu")
		(net "M_C_CPU0_SA_DQ<21>")
	)
	(segment
		(start 282.165298 -288.990278)
		(end 282.165298 -289.358832)
		(width 0.18288)
		(layer "In4.Cu")
		(net "M_C_CPU0_SA_DQ<21>")
	)
	(segment
		(start 282.165298 -289.358832)
		(end 281.982418 -289.541712)
		(width 0.18288)
		(layer "In4.Cu")
		(net "M_C_CPU0_SA_DQ<21>")
	)
	(segment
		(start 336.477864 -265.803634)
		(end 336.477864 -265.803888)
		(width 0.088646)
		(layer "In4.Cu")
		(net "M_C_CPU0_SA_DQ<21>")
	)
	(segment
		(start 294.35806 -289.541966)
		(end 293.328598 -288.512504)
		(width 0.18288)
		(layer "In4.Cu")
		(net "M_C_CPU0_SA_DQ<21>")
	)
	(segment
		(start 336.857086 -265.806428)
		(end 336.852514 -265.803634)
		(width 0.088646)
		(layer "In4.Cu")
		(net "M_C_CPU0_SA_DQ<21>")
	)
	(segment
		(start 281.982418 -289.541712)
		(end 280.241756 -289.541712)
		(width 0.18288)
		(layer "In4.Cu")
		(net "M_C_CPU0_SA_DQ<21>")
	)
	(segment
		(start 287.830768 -289.541712)
		(end 283.039058 -289.541712)
		(width 0.18288)
		(layer "In4.Cu")
		(net "M_C_CPU0_SA_DQ<21>")
	)
	(segment
		(start 338.737956 -265.80719)
		(end 338.732114 -265.803634)
		(width 0.088646)
		(layer "In4.Cu")
		(net "M_C_CPU0_SA_DQ<21>")
	)
	(segment
		(start 308.455314 -286.405066)
		(end 307.955442 -286.904938)
		(width 0.18288)
		(layer "In4.Cu")
		(net "M_C_CPU0_SA_DQ<21>")
	)
	(segment
		(start 311.910222 -285.378652)
		(end 311.328308 -285.378652)
		(width 0.18288)
		(layer "In4.Cu")
		(net "M_C_CPU0_SA_DQ<21>")
	)
	(segment
		(start 310.301894 -286.405066)
		(end 308.455314 -286.405066)
		(width 0.18288)
		(layer "In4.Cu")
		(net "M_C_CPU0_SA_DQ<21>")
	)
	(segment
		(start 337.79587 -265.80592)
		(end 337.792314 -265.803634)
		(width 0.088646)
		(layer "In4.Cu")
		(net "M_C_CPU0_SA_DQ<21>")
	)
	(segment
		(start 331.700886 -265.86307)
		(end 331.553058 -266.010898)
		(width 0.088646)
		(layer "In4.Cu")
		(net "M_C_CPU0_SA_DQ<21>")
	)
	(segment
		(start 282.348178 -288.807398)
		(end 282.165298 -288.990278)
		(width 0.18288)
		(layer "In4.Cu")
		(net "M_C_CPU0_SA_DQ<21>")
	)
	(segment
		(start 336.852514 -265.803634)
		(end 336.846672 -265.800332)
		(width 0.088646)
		(layer "In4.Cu")
		(net "M_C_CPU0_SA_DQ<21>")
	)
	(segment
		(start 313.600592 -283.688282)
		(end 311.910222 -285.378652)
		(width 0.18288)
		(layer "In4.Cu")
		(net "M_C_CPU0_SA_DQ<21>")
	)
	(segment
		(start 280.241756 -289.541712)
		(end 279.816814 -289.966654)
		(width 0.18288)
		(layer "In4.Cu")
		(net "M_C_CPU0_SA_DQ<21>")
	)
	(segment
		(start 317.44158 -278.536654)
		(end 315.938662 -282.164028)
		(width 0.18288)
		(layer "In4.Cu")
		(net "M_C_CPU0_SA_DQ<21>")
	)
	(segment
		(start 297.342814 -289.541966)
		(end 294.35806 -289.541966)
		(width 0.18288)
		(layer "In4.Cu")
		(net "M_C_CPU0_SA_DQ<21>")
	)
	(arc
		(start 338.726272 -265.800332)
		(mid 338.541417 -265.753382)
		(end 338.357464 -265.803634)
		(width 0.088646)
		(layer "In4.Cu")
		(net "M_C_CPU0_SA_DQ<21>")
	)
	(arc
		(start 337.792314 -265.803634)
		(mid 337.605006 -265.753525)
		(end 337.417664 -265.803634)
		(width 0.088646)
		(layer "In4.Cu")
		(net "M_C_CPU0_SA_DQ<21>")
	)
	(arc
		(start 334.598264 -265.803888)
		(mid 334.315562 -265.87963)
		(end 334.03286 -265.803888)
		(width 0.088646)
		(layer "In4.Cu")
		(net "M_C_CPU0_SA_DQ<21>")
	)
	(arc
		(start 338.357464 -265.803634)
		(mid 338.076983 -265.879406)
		(end 337.79587 -265.80592)
		(width 0.088646)
		(layer "In4.Cu")
		(net "M_C_CPU0_SA_DQ<21>")
	)
	(arc
		(start 334.03286 -265.803888)
		(mid 333.845662 -265.753745)
		(end 333.658464 -265.803888)
		(width 0.088646)
		(layer "In4.Cu")
		(net "M_C_CPU0_SA_DQ<21>")
	)
	(arc
		(start 332.718664 -265.803888)
		(mid 332.435962 -265.87963)
		(end 332.15326 -265.803888)
		(width 0.088646)
		(layer "In4.Cu")
		(net "M_C_CPU0_SA_DQ<21>")
	)
	(arc
		(start 336.846672 -265.800332)
		(mid 336.661817 -265.753382)
		(end 336.477864 -265.803634)
		(width 0.088646)
		(layer "In4.Cu")
		(net "M_C_CPU0_SA_DQ<21>")
	)
	(arc
		(start 339.297264 -265.803634)
		(mid 339.01809 -265.879399)
		(end 338.737956 -265.80719)
		(width 0.088646)
		(layer "In4.Cu")
		(net "M_C_CPU0_SA_DQ<21>")
	)
	(arc
		(start 340.424262 -266.128246)
		(mid 340.040458 -265.994413)
		(end 339.67928 -265.807952)
		(width 0.088646)
		(layer "In4.Cu")
		(net "M_C_CPU0_SA_DQ<21>")
	)
	(arc
		(start 335.538064 -265.803888)
		(mid 335.255362 -265.87963)
		(end 334.97266 -265.803888)
		(width 0.088646)
		(layer "In4.Cu")
		(net "M_C_CPU0_SA_DQ<21>")
	)
	(arc
		(start 333.658464 -265.803888)
		(mid 333.375762 -265.87963)
		(end 333.09306 -265.803888)
		(width 0.088646)
		(layer "In4.Cu")
		(net "M_C_CPU0_SA_DQ<21>")
	)
	(arc
		(start 339.666072 -265.800332)
		(mid 339.481217 -265.753382)
		(end 339.297264 -265.803634)
		(width 0.088646)
		(layer "In4.Cu")
		(net "M_C_CPU0_SA_DQ<21>")
	)
	(arc
		(start 334.97266 -265.803888)
		(mid 334.785462 -265.753745)
		(end 334.598264 -265.803888)
		(width 0.088646)
		(layer "In4.Cu")
		(net "M_C_CPU0_SA_DQ<21>")
	)
	(arc
		(start 337.417664 -265.803634)
		(mid 337.13775 -265.879403)
		(end 336.857086 -265.806428)
		(width 0.088646)
		(layer "In4.Cu")
		(net "M_C_CPU0_SA_DQ<21>")
	)
	(arc
		(start 333.09306 -265.803888)
		(mid 332.905862 -265.753745)
		(end 332.718664 -265.803888)
		(width 0.088646)
		(layer "In4.Cu")
		(net "M_C_CPU0_SA_DQ<21>")
	)
	(arc
		(start 336.477864 -265.803888)
		(mid 336.195162 -265.87963)
		(end 335.91246 -265.803888)
		(width 0.088646)
		(layer "In4.Cu")
		(net "M_C_CPU0_SA_DQ<21>")
	)
	(arc
		(start 332.15326 -265.803888)
		(mid 331.966062 -265.753745)
		(end 331.778864 -265.803888)
		(width 0.088646)
		(layer "In4.Cu")
		(net "M_C_CPU0_SA_DQ<21>")
	)
	(arc
		(start 335.91246 -265.803888)
		(mid 335.725262 -265.753745)
		(end 335.538064 -265.803888)
		(width 0.088646)
		(layer "In4.Cu")
		(net "M_C_CPU0_SA_DQ<21>")
	)
	(arc
		(start 331.778864 -265.803888)
		(mid 331.737934 -265.830921)
		(end 331.700886 -265.86307)
		(width 0.088646)
		(layer "In4.Cu")
		(net "M_C_CPU0_SA_DQ<21>")
	)
	(segment
		(start 276.469094 -291.241734)
		(end 274.40001 -291.241734)
		(width 0.1016)
		(layer "F.Cu")
		(net "M_C_CPU0_SA_DQ<20>")
	)
	(segment
		(start 273.37258 -291.443156)
		(end 273.37258 -291.732716)
		(width 0.20066)
		(layer "F.Cu")
		(net "M_C_CPU0_SA_DQ<20>")
	)
	(segment
		(start 273.19986 -291.905436)
		(end 272.741136 -291.905436)
		(width 0.20066)
		(layer "F.Cu")
		(net "M_C_CPU0_SA_DQ<20>")
	)
	(segment
		(start 272.741136 -291.905436)
		(end 272.502376 -291.666676)
		(width 0.20066)
		(layer "F.Cu")
		(net "M_C_CPU0_SA_DQ<20>")
	)
	(segment
		(start 279.816814 -291.666676)
		(end 278.711914 -291.666676)
		(width 0.20066)
		(layer "F.Cu")
		(net "M_C_CPU0_SA_DQ<20>")
	)
	(segment
		(start 274.143978 -291.233606)
		(end 273.58213 -291.233606)
		(width 0.20066)
		(layer "F.Cu")
		(net "M_C_CPU0_SA_DQ<20>")
	)
	(segment
		(start 274.152106 -291.241734)
		(end 274.143978 -291.233606)
		(width 0.101854)
		(layer "F.Cu")
		(net "M_C_CPU0_SA_DQ<20>")
	)
	(segment
		(start 272.502376 -291.666676)
		(end 271.168114 -291.666676)
		(width 0.20066)
		(layer "F.Cu")
		(net "M_C_CPU0_SA_DQ<20>")
	)
	(segment
		(start 274.40001 -291.241734)
		(end 274.152106 -291.241734)
		(width 0.101854)
		(layer "F.Cu")
		(net "M_C_CPU0_SA_DQ<20>")
	)
	(segment
		(start 273.37258 -291.732716)
		(end 273.19986 -291.905436)
		(width 0.20066)
		(layer "F.Cu")
		(net "M_C_CPU0_SA_DQ<20>")
	)
	(segment
		(start 276.917912 -291.241734)
		(end 276.469094 -291.241734)
		(width 0.20066)
		(layer "F.Cu")
		(net "M_C_CPU0_SA_DQ<20>")
	)
	(segment
		(start 273.58213 -291.233606)
		(end 273.37258 -291.443156)
		(width 0.20066)
		(layer "F.Cu")
		(net "M_C_CPU0_SA_DQ<20>")
	)
	(segment
		(start 339.954616 -266.406122)
		(end 339.954616 -266.941808)
		(width 0.20066)
		(layer "F.Cu")
		(net "M_C_CPU0_SA_DQ<20>")
	)
	(segment
		(start 339.954362 -266.405868)
		(end 339.954616 -266.406122)
		(width 0.20066)
		(layer "F.Cu")
		(net "M_C_CPU0_SA_DQ<20>")
	)
	(segment
		(start 277.342854 -291.666676)
		(end 276.917912 -291.241734)
		(width 0.20066)
		(layer "F.Cu")
		(net "M_C_CPU0_SA_DQ<20>")
	)
	(segment
		(start 278.711914 -291.666676)
		(end 277.342854 -291.666676)
		(width 0.20066)
		(layer "F.Cu")
		(net "M_C_CPU0_SA_DQ<20>")
	)
	(segment
		(start 289.425634 -290.830508)
		(end 289.014408 -291.241734)
		(width 0.18288)
		(layer "In4.Cu")
		(net "M_C_CPU0_SA_DQ<20>")
	)
	(segment
		(start 307.992018 -288.515298)
		(end 307.719222 -288.515298)
		(width 0.18288)
		(layer "In4.Cu")
		(net "M_C_CPU0_SA_DQ<20>")
	)
	(segment
		(start 290.163504 -291.013388)
		(end 289.980624 -290.830508)
		(width 0.18288)
		(layer "In4.Cu")
		(net "M_C_CPU0_SA_DQ<20>")
	)
	(segment
		(start 300.704504 -290.39185)
		(end 298.130214 -290.39185)
		(width 0.18288)
		(layer "In4.Cu")
		(net "M_C_CPU0_SA_DQ<20>")
	)
	(segment
		(start 310.430926 -287.84804)
		(end 308.659276 -287.84804)
		(width 0.18288)
		(layer "In4.Cu")
		(net "M_C_CPU0_SA_DQ<20>")
	)
	(segment
		(start 291.037264 -290.830508)
		(end 290.854384 -291.013388)
		(width 0.18288)
		(layer "In4.Cu")
		(net "M_C_CPU0_SA_DQ<20>")
	)
	(segment
		(start 304.725832 -291.025834)
		(end 303.595278 -291.025834)
		(width 0.18288)
		(layer "In4.Cu")
		(net "M_C_CPU0_SA_DQ<20>")
	)
	(segment
		(start 338.833206 -266.614148)
		(end 338.827364 -266.617704)
		(width 0.088646)
		(layer "In4.Cu")
		(net "M_C_CPU0_SA_DQ<20>")
	)
	(segment
		(start 306.723542 -289.510978)
		(end 306.240688 -289.510978)
		(width 0.18288)
		(layer "In4.Cu")
		(net "M_C_CPU0_SA_DQ<20>")
	)
	(segment
		(start 289.980624 -290.830508)
		(end 289.425634 -290.830508)
		(width 0.18288)
		(layer "In4.Cu")
		(net "M_C_CPU0_SA_DQ<20>")
	)
	(segment
		(start 339.598254 -266.846304)
		(end 339.202014 -266.61745)
		(width 0.088646)
		(layer "In4.Cu")
		(net "M_C_CPU0_SA_DQ<20>")
	)
	(segment
		(start 329.39863 -268.0081)
		(end 318.363854 -279.042876)
		(width 0.18288)
		(layer "In4.Cu")
		(net "M_C_CPU0_SA_DQ<20>")
	)
	(segment
		(start 314.4012 -285.391098)
		(end 313.676284 -285.391098)
		(width 0.18288)
		(layer "In4.Cu")
		(net "M_C_CPU0_SA_DQ<20>")
	)
	(segment
		(start 290.163504 -291.568378)
		(end 290.163504 -291.013388)
		(width 0.18288)
		(layer "In4.Cu")
		(net "M_C_CPU0_SA_DQ<20>")
	)
	(segment
		(start 313.676284 -285.391098)
		(end 312.076592 -286.99079)
		(width 0.18288)
		(layer "In4.Cu")
		(net "M_C_CPU0_SA_DQ<20>")
	)
	(segment
		(start 280.241756 -291.241734)
		(end 279.816814 -291.666676)
		(width 0.18288)
		(layer "In4.Cu")
		(net "M_C_CPU0_SA_DQ<20>")
	)
	(segment
		(start 311.288176 -286.99079)
		(end 310.430926 -287.84804)
		(width 0.18288)
		(layer "In4.Cu")
		(net "M_C_CPU0_SA_DQ<20>")
	)
	(segment
		(start 316.67577 -283.116528)
		(end 314.4012 -285.391098)
		(width 0.18288)
		(layer "In4.Cu")
		(net "M_C_CPU0_SA_DQ<20>")
	)
	(segment
		(start 294.092884 -291.241988)
		(end 293.215314 -290.364418)
		(width 0.18288)
		(layer "In4.Cu")
		(net "M_C_CPU0_SA_DQ<20>")
	)
	(segment
		(start 290.671504 -291.751258)
		(end 290.346384 -291.751258)
		(width 0.18288)
		(layer "In4.Cu")
		(net "M_C_CPU0_SA_DQ<20>")
	)
	(segment
		(start 293.215314 -290.364418)
		(end 292.35146 -290.364418)
		(width 0.18288)
		(layer "In4.Cu")
		(net "M_C_CPU0_SA_DQ<20>")
	)
	(segment
		(start 312.076592 -286.99079)
		(end 311.288176 -286.99079)
		(width 0.18288)
		(layer "In4.Cu")
		(net "M_C_CPU0_SA_DQ<20>")
	)
	(segment
		(start 318.363854 -279.042876)
		(end 316.67577 -283.116528)
		(width 0.18288)
		(layer "In4.Cu")
		(net "M_C_CPU0_SA_DQ<20>")
	)
	(segment
		(start 289.014408 -291.241734)
		(end 280.241756 -291.241734)
		(width 0.18288)
		(layer "In4.Cu")
		(net "M_C_CPU0_SA_DQ<20>")
	)
	(segment
		(start 298.130214 -290.39185)
		(end 297.280076 -291.241988)
		(width 0.18288)
		(layer "In4.Cu")
		(net "M_C_CPU0_SA_DQ<20>")
	)
	(segment
		(start 332.170786 -266.676632)
		(end 332.170786 -266.676886)
		(width 0.088646)
		(layer "In4.Cu")
		(net "M_C_CPU0_SA_DQ<20>")
	)
	(segment
		(start 306.240688 -289.510978)
		(end 304.725832 -291.025834)
		(width 0.18288)
		(layer "In4.Cu")
		(net "M_C_CPU0_SA_DQ<20>")
	)
	(segment
		(start 303.595278 -291.025834)
		(end 302.961294 -290.39185)
		(width 0.18288)
		(layer "In4.Cu")
		(net "M_C_CPU0_SA_DQ<20>")
	)
	(segment
		(start 290.854384 -291.568378)
		(end 290.671504 -291.751258)
		(width 0.18288)
		(layer "In4.Cu")
		(net "M_C_CPU0_SA_DQ<20>")
	)
	(segment
		(start 301.036482 -290.723828)
		(end 300.704504 -290.39185)
		(width 0.18288)
		(layer "In4.Cu")
		(net "M_C_CPU0_SA_DQ<20>")
	)
	(segment
		(start 302.961294 -290.39185)
		(end 301.761144 -290.39185)
		(width 0.18288)
		(layer "In4.Cu")
		(net "M_C_CPU0_SA_DQ<20>")
	)
	(segment
		(start 292.35146 -290.364418)
		(end 291.88537 -290.830508)
		(width 0.18288)
		(layer "In4.Cu")
		(net "M_C_CPU0_SA_DQ<20>")
	)
	(segment
		(start 332.170786 -266.676886)
		(end 330.839572 -268.0081)
		(width 0.088646)
		(layer "In4.Cu")
		(net "M_C_CPU0_SA_DQ<20>")
	)
	(segment
		(start 336.952082 -266.61491)
		(end 336.947764 -266.617704)
		(width 0.088646)
		(layer "In4.Cu")
		(net "M_C_CPU0_SA_DQ<20>")
	)
	(segment
		(start 290.854384 -291.013388)
		(end 290.854384 -291.568378)
		(width 0.18288)
		(layer "In4.Cu")
		(net "M_C_CPU0_SA_DQ<20>")
	)
	(segment
		(start 330.724256 -268.0081)
		(end 329.39863 -268.0081)
		(width 0.18288)
		(layer "In4.Cu")
		(net "M_C_CPU0_SA_DQ<20>")
	)
	(segment
		(start 308.659276 -287.84804)
		(end 307.992018 -288.515298)
		(width 0.18288)
		(layer "In4.Cu")
		(net "M_C_CPU0_SA_DQ<20>")
	)
	(segment
		(start 301.429166 -290.723828)
		(end 301.036482 -290.723828)
		(width 0.18288)
		(layer "In4.Cu")
		(net "M_C_CPU0_SA_DQ<20>")
	)
	(segment
		(start 301.761144 -290.39185)
		(end 301.429166 -290.723828)
		(width 0.18288)
		(layer "In4.Cu")
		(net "M_C_CPU0_SA_DQ<20>")
	)
	(segment
		(start 307.719222 -288.515298)
		(end 306.723542 -289.510978)
		(width 0.18288)
		(layer "In4.Cu")
		(net "M_C_CPU0_SA_DQ<20>")
	)
	(segment
		(start 297.280076 -291.241988)
		(end 294.092884 -291.241988)
		(width 0.18288)
		(layer "In4.Cu")
		(net "M_C_CPU0_SA_DQ<20>")
	)
	(segment
		(start 330.839572 -268.0081)
		(end 330.724256 -268.0081)
		(width 0.088646)
		(layer "In4.Cu")
		(net "M_C_CPU0_SA_DQ<20>")
	)
	(segment
		(start 291.88537 -290.830508)
		(end 291.037264 -290.830508)
		(width 0.18288)
		(layer "In4.Cu")
		(net "M_C_CPU0_SA_DQ<20>")
	)
	(segment
		(start 290.346384 -291.751258)
		(end 290.163504 -291.568378)
		(width 0.18288)
		(layer "In4.Cu")
		(net "M_C_CPU0_SA_DQ<20>")
	)
	(segment
		(start 337.32216 -266.617704)
		(end 337.322414 -266.61745)
		(width 0.088646)
		(layer "In4.Cu")
		(net "M_C_CPU0_SA_DQ<20>")
	)
	(arc
		(start 336.38236 -266.617704)
		(mid 336.195162 -266.567527)
		(end 336.007964 -266.617704)
		(width 0.088646)
		(layer "In4.Cu")
		(net "M_C_CPU0_SA_DQ<20>")
	)
	(arc
		(start 332.248764 -266.617704)
		(mid 332.207838 -266.644606)
		(end 332.170786 -266.676632)
		(width 0.088646)
		(layer "In4.Cu")
		(net "M_C_CPU0_SA_DQ<20>")
	)
	(arc
		(start 337.887564 -266.617704)
		(mid 337.604862 -266.69348)
		(end 337.32216 -266.617704)
		(width 0.088646)
		(layer "In4.Cu")
		(net "M_C_CPU0_SA_DQ<20>")
	)
	(arc
		(start 337.322414 -266.61745)
		(mid 337.137577 -266.567189)
		(end 336.952082 -266.61491)
		(width 0.088646)
		(layer "In4.Cu")
		(net "M_C_CPU0_SA_DQ<20>")
	)
	(arc
		(start 336.947764 -266.617704)
		(mid 336.665062 -266.69348)
		(end 336.38236 -266.617704)
		(width 0.088646)
		(layer "In4.Cu")
		(net "M_C_CPU0_SA_DQ<20>")
	)
	(arc
		(start 335.068164 -266.617704)
		(mid 334.785462 -266.69348)
		(end 334.50276 -266.617704)
		(width 0.088646)
		(layer "In4.Cu")
		(net "M_C_CPU0_SA_DQ<20>")
	)
	(arc
		(start 338.26196 -266.617704)
		(mid 338.074762 -266.567527)
		(end 337.887564 -266.617704)
		(width 0.088646)
		(layer "In4.Cu")
		(net "M_C_CPU0_SA_DQ<20>")
	)
	(arc
		(start 334.50276 -266.617704)
		(mid 334.315562 -266.567527)
		(end 334.128364 -266.617704)
		(width 0.088646)
		(layer "In4.Cu")
		(net "M_C_CPU0_SA_DQ<20>")
	)
	(arc
		(start 333.188564 -266.617704)
		(mid 332.905862 -266.69348)
		(end 332.62316 -266.617704)
		(width 0.088646)
		(layer "In4.Cu")
		(net "M_C_CPU0_SA_DQ<20>")
	)
	(arc
		(start 335.44256 -266.617704)
		(mid 335.255362 -266.567527)
		(end 335.068164 -266.617704)
		(width 0.088646)
		(layer "In4.Cu")
		(net "M_C_CPU0_SA_DQ<20>")
	)
	(arc
		(start 336.007964 -266.617704)
		(mid 335.725262 -266.69348)
		(end 335.44256 -266.617704)
		(width 0.088646)
		(layer "In4.Cu")
		(net "M_C_CPU0_SA_DQ<20>")
	)
	(arc
		(start 339.954616 -266.941808)
		(mid 339.770133 -266.917559)
		(end 339.598254 -266.846304)
		(width 0.088646)
		(layer "In4.Cu")
		(net "M_C_CPU0_SA_DQ<20>")
	)
	(arc
		(start 332.62316 -266.617704)
		(mid 332.435962 -266.567527)
		(end 332.248764 -266.617704)
		(width 0.088646)
		(layer "In4.Cu")
		(net "M_C_CPU0_SA_DQ<20>")
	)
	(arc
		(start 334.128364 -266.617704)
		(mid 333.845662 -266.69348)
		(end 333.56296 -266.617704)
		(width 0.088646)
		(layer "In4.Cu")
		(net "M_C_CPU0_SA_DQ<20>")
	)
	(arc
		(start 338.827364 -266.617704)
		(mid 338.544662 -266.69348)
		(end 338.26196 -266.617704)
		(width 0.088646)
		(layer "In4.Cu")
		(net "M_C_CPU0_SA_DQ<20>")
	)
	(arc
		(start 339.202014 -266.61745)
		(mid 339.01806 -266.567321)
		(end 338.833206 -266.614148)
		(width 0.088646)
		(layer "In4.Cu")
		(net "M_C_CPU0_SA_DQ<20>")
	)
	(arc
		(start 333.56296 -266.617704)
		(mid 333.375762 -266.567527)
		(end 333.188564 -266.617704)
		(width 0.088646)
		(layer "In4.Cu")
		(net "M_C_CPU0_SA_DQ<20>")
	)
	(segment
		(start 276.138386 -314.19165)
		(end 274.152868 -314.19165)
		(width 0.1016)
		(layer "F.Cu")
		(net "M_C_CPU0_SA_DQ<1>")
	)
	(segment
		(start 274.152868 -314.19165)
		(end 274.143978 -314.18276)
		(width 0.1016)
		(layer "F.Cu")
		(net "M_C_CPU0_SA_DQ<1>")
	)
	(segment
		(start 274.143978 -314.18276)
		(end 273.53514 -314.18276)
		(width 0.20066)
		(layer "F.Cu")
		(net "M_C_CPU0_SA_DQ<1>")
	)
	(segment
		(start 273.37258 -314.34532)
		(end 273.37258 -314.673488)
		(width 0.20066)
		(layer "F.Cu")
		(net "M_C_CPU0_SA_DQ<1>")
	)
	(segment
		(start 277.072598 -314.616592)
		(end 276.647656 -314.19165)
		(width 0.20066)
		(layer "F.Cu")
		(net "M_C_CPU0_SA_DQ<1>")
	)
	(segment
		(start 276.469094 -314.19165)
		(end 276.138386 -314.19165)
		(width 0.101854)
		(layer "F.Cu")
		(net "M_C_CPU0_SA_DQ<1>")
	)
	(segment
		(start 273.37258 -314.673488)
		(end 273.218148 -314.82792)
		(width 0.20066)
		(layer "F.Cu")
		(net "M_C_CPU0_SA_DQ<1>")
	)
	(segment
		(start 273.218148 -314.82792)
		(end 272.713704 -314.82792)
		(width 0.20066)
		(layer "F.Cu")
		(net "M_C_CPU0_SA_DQ<1>")
	)
	(segment
		(start 272.713704 -314.82792)
		(end 272.502376 -314.616592)
		(width 0.20066)
		(layer "F.Cu")
		(net "M_C_CPU0_SA_DQ<1>")
	)
	(segment
		(start 279.816814 -314.616592)
		(end 278.711914 -314.616592)
		(width 0.20066)
		(layer "F.Cu")
		(net "M_C_CPU0_SA_DQ<1>")
	)
	(segment
		(start 339.954362 -277.800562)
		(end 339.954362 -278.336248)
		(width 0.20066)
		(layer "F.Cu")
		(net "M_C_CPU0_SA_DQ<1>")
	)
	(segment
		(start 278.711914 -314.616592)
		(end 277.072598 -314.616592)
		(width 0.20066)
		(layer "F.Cu")
		(net "M_C_CPU0_SA_DQ<1>")
	)
	(segment
		(start 273.53514 -314.18276)
		(end 273.37258 -314.34532)
		(width 0.20066)
		(layer "F.Cu")
		(net "M_C_CPU0_SA_DQ<1>")
	)
	(segment
		(start 339.954362 -278.336248)
		(end 339.954616 -278.336502)
		(width 0.20066)
		(layer "F.Cu")
		(net "M_C_CPU0_SA_DQ<1>")
	)
	(segment
		(start 276.647656 -314.19165)
		(end 276.469094 -314.19165)
		(width 0.20066)
		(layer "F.Cu")
		(net "M_C_CPU0_SA_DQ<1>")
	)
	(segment
		(start 272.502376 -314.616592)
		(end 271.168114 -314.616592)
		(width 0.20066)
		(layer "F.Cu")
		(net "M_C_CPU0_SA_DQ<1>")
	)
	(segment
		(start 299.4787 -317.591694)
		(end 294.160194 -317.591694)
		(width 0.18288)
		(layer "In4.Cu")
		(net "M_C_CPU0_SA_DQ<1>")
	)
	(segment
		(start 313.616594 -313.390026)
		(end 312.9407 -314.06592)
		(width 0.18288)
		(layer "In4.Cu")
		(net "M_C_CPU0_SA_DQ<1>")
	)
	(segment
		(start 337.230466 -284.025086)
		(end 337.230466 -284.033722)
		(width 0.088646)
		(layer "In4.Cu")
		(net "M_C_CPU0_SA_DQ<1>")
	)
	(segment
		(start 338.827618 -281.267662)
		(end 338.827364 -281.267662)
		(width 0.088646)
		(layer "In4.Cu")
		(net "M_C_CPU0_SA_DQ<1>")
	)
	(segment
		(start 314.45708 -313.390026)
		(end 313.616594 -313.390026)
		(width 0.18288)
		(layer "In4.Cu")
		(net "M_C_CPU0_SA_DQ<1>")
	)
	(segment
		(start 302.810672 -316.617096)
		(end 300.113192 -316.617096)
		(width 0.18288)
		(layer "In4.Cu")
		(net "M_C_CPU0_SA_DQ<1>")
	)
	(segment
		(start 339.579966 -279.964134)
		(end 339.579966 -279.978358)
		(width 0.088646)
		(layer "In4.Cu")
		(net "M_C_CPU0_SA_DQ<1>")
	)
	(segment
		(start 299.63872 -317.091568)
		(end 299.63872 -317.431674)
		(width 0.18288)
		(layer "In4.Cu")
		(net "M_C_CPU0_SA_DQ<1>")
	)
	(segment
		(start 320.998342 -304.773838)
		(end 320.998342 -306.848764)
		(width 0.18288)
		(layer "In4.Cu")
		(net "M_C_CPU0_SA_DQ<1>")
	)
	(segment
		(start 308.093872 -316.007496)
		(end 307.70068 -316.007496)
		(width 0.18288)
		(layer "In4.Cu")
		(net "M_C_CPU0_SA_DQ<1>")
	)
	(segment
		(start 311.30875 -314.06592)
		(end 309.135018 -314.96635)
		(width 0.18288)
		(layer "In4.Cu")
		(net "M_C_CPU0_SA_DQ<1>")
	)
	(segment
		(start 332.884526 -287.549336)
		(end 332.790038 -287.549336)
		(width 0.18288)
		(layer "In4.Cu")
		(net "M_C_CPU0_SA_DQ<1>")
	)
	(segment
		(start 338.369656 -283.702252)
		(end 338.357464 -283.709364)
		(width 0.088646)
		(layer "In4.Cu")
		(net "M_C_CPU0_SA_DQ<1>")
	)
	(segment
		(start 293.312342 -316.743842)
		(end 288.998914 -316.743842)
		(width 0.18288)
		(layer "In4.Cu")
		(net "M_C_CPU0_SA_DQ<1>")
	)
	(segment
		(start 294.160194 -317.591694)
		(end 293.312342 -316.743842)
		(width 0.18288)
		(layer "In4.Cu")
		(net "M_C_CPU0_SA_DQ<1>")
	)
	(segment
		(start 333.58074 -287.024318)
		(end 333.055722 -287.549336)
		(width 0.088646)
		(layer "In4.Cu")
		(net "M_C_CPU0_SA_DQ<1>")
	)
	(segment
		(start 280.24201 -315.041788)
		(end 279.816814 -314.616592)
		(width 0.18288)
		(layer "In4.Cu")
		(net "M_C_CPU0_SA_DQ<1>")
	)
	(segment
		(start 338.827364 -281.916378)
		(end 338.83346 -281.919934)
		(width 0.088646)
		(layer "In4.Cu")
		(net "M_C_CPU0_SA_DQ<1>")
	)
	(segment
		(start 339.288374 -279.469596)
		(end 339.297264 -279.474676)
		(width 0.088646)
		(layer "In4.Cu")
		(net "M_C_CPU0_SA_DQ<1>")
	)
	(segment
		(start 339.510116 -278.640032)
		(end 339.430106 -278.720042)
		(width 0.088646)
		(layer "In4.Cu")
		(net "M_C_CPU0_SA_DQ<1>")
	)
	(segment
		(start 288.466784 -315.875416)
		(end 287.633156 -315.041788)
		(width 0.18288)
		(layer "In4.Cu")
		(net "M_C_CPU0_SA_DQ<1>")
	)
	(segment
		(start 339.297264 -280.453846)
		(end 339.288374 -280.458926)
		(width 0.088646)
		(layer "In4.Cu")
		(net "M_C_CPU0_SA_DQ<1>")
	)
	(segment
		(start 288.998914 -316.743842)
		(end 288.466784 -316.211712)
		(width 0.18288)
		(layer "In4.Cu")
		(net "M_C_CPU0_SA_DQ<1>")
	)
	(segment
		(start 299.63872 -317.431674)
		(end 299.4787 -317.591694)
		(width 0.18288)
		(layer "In4.Cu")
		(net "M_C_CPU0_SA_DQ<1>")
	)
	(segment
		(start 339.297264 -279.474676)
		(end 339.30336 -279.478232)
		(width 0.088646)
		(layer "In4.Cu")
		(net "M_C_CPU0_SA_DQ<1>")
	)
	(segment
		(start 333.940912 -286.475424)
		(end 333.940912 -286.48533)
		(width 0.088646)
		(layer "In4.Cu")
		(net "M_C_CPU0_SA_DQ<1>")
	)
	(segment
		(start 305.437032 -315.176916)
		(end 304.872644 -315.741304)
		(width 0.18288)
		(layer "In4.Cu")
		(net "M_C_CPU0_SA_DQ<1>")
	)
	(segment
		(start 336.477864 -285.336996)
		(end 336.468974 -285.342076)
		(width 0.088646)
		(layer "In4.Cu")
		(net "M_C_CPU0_SA_DQ<1>")
	)
	(segment
		(start 287.633156 -315.041788)
		(end 280.24201 -315.041788)
		(width 0.18288)
		(layer "In4.Cu")
		(net "M_C_CPU0_SA_DQ<1>")
	)
	(segment
		(start 339.109812 -280.778204)
		(end 339.109812 -280.793698)
		(width 0.088646)
		(layer "In4.Cu")
		(net "M_C_CPU0_SA_DQ<1>")
	)
	(segment
		(start 312.9407 -314.06592)
		(end 311.30875 -314.06592)
		(width 0.18288)
		(layer "In4.Cu")
		(net "M_C_CPU0_SA_DQ<1>")
	)
	(segment
		(start 306.8701 -315.176916)
		(end 305.437032 -315.176916)
		(width 0.18288)
		(layer "In4.Cu")
		(net "M_C_CPU0_SA_DQ<1>")
	)
	(segment
		(start 338.821268 -282.899104)
		(end 338.818728 -282.900628)
		(width 0.088646)
		(layer "In4.Cu")
		(net "M_C_CPU0_SA_DQ<1>")
	)
	(segment
		(start 332.790038 -287.549336)
		(end 331.51953 -288.819844)
		(width 0.18288)
		(layer "In4.Cu")
		(net "M_C_CPU0_SA_DQ<1>")
	)
	(segment
		(start 304.872644 -315.741304)
		(end 303.686464 -315.741304)
		(width 0.18288)
		(layer "In4.Cu")
		(net "M_C_CPU0_SA_DQ<1>")
	)
	(segment
		(start 336.950558 -284.521656)
		(end 336.947764 -284.52318)
		(width 0.088646)
		(layer "In4.Cu")
		(net "M_C_CPU0_SA_DQ<1>")
	)
	(segment
		(start 338.827364 -281.267662)
		(end 338.818474 -281.272742)
		(width 0.088646)
		(layer "In4.Cu")
		(net "M_C_CPU0_SA_DQ<1>")
	)
	(segment
		(start 336.760312 -284.847538)
		(end 336.760312 -284.857444)
		(width 0.088646)
		(layer "In4.Cu")
		(net "M_C_CPU0_SA_DQ<1>")
	)
	(segment
		(start 303.686464 -315.741304)
		(end 302.810672 -316.617096)
		(width 0.18288)
		(layer "In4.Cu")
		(net "M_C_CPU0_SA_DQ<1>")
	)
	(segment
		(start 300.113192 -316.617096)
		(end 299.63872 -317.091568)
		(width 0.18288)
		(layer "In4.Cu")
		(net "M_C_CPU0_SA_DQ<1>")
	)
	(segment
		(start 327.676002 -298.096178)
		(end 320.998342 -304.773838)
		(width 0.18288)
		(layer "In4.Cu")
		(net "M_C_CPU0_SA_DQ<1>")
	)
	(segment
		(start 338.818474 -281.911298)
		(end 338.827364 -281.916378)
		(width 0.088646)
		(layer "In4.Cu")
		(net "M_C_CPU0_SA_DQ<1>")
	)
	(segment
		(start 334.128364 -286.151066)
		(end 334.119474 -286.156146)
		(width 0.088646)
		(layer "In4.Cu")
		(net "M_C_CPU0_SA_DQ<1>")
	)
	(segment
		(start 339.110066 -282.405836)
		(end 339.110066 -282.42006)
		(width 0.088646)
		(layer "In4.Cu")
		(net "M_C_CPU0_SA_DQ<1>")
	)
	(segment
		(start 339.599524 -278.640032)
		(end 339.510116 -278.640032)
		(width 0.088646)
		(layer "In4.Cu")
		(net "M_C_CPU0_SA_DQ<1>")
	)
	(segment
		(start 307.70068 -316.007496)
		(end 306.8701 -315.176916)
		(width 0.18288)
		(layer "In4.Cu")
		(net "M_C_CPU0_SA_DQ<1>")
	)
	(segment
		(start 338.827364 -282.895548)
		(end 338.821268 -282.899104)
		(width 0.088646)
		(layer "In4.Cu")
		(net "M_C_CPU0_SA_DQ<1>")
	)
	(segment
		(start 309.135018 -314.96635)
		(end 308.093872 -316.007496)
		(width 0.18288)
		(layer "In4.Cu")
		(net "M_C_CPU0_SA_DQ<1>")
	)
	(segment
		(start 339.612732 -278.626824)
		(end 339.599524 -278.640032)
		(width 0.088646)
		(layer "In4.Cu")
		(net "M_C_CPU0_SA_DQ<1>")
	)
	(segment
		(start 336.95386 -284.519624)
		(end 336.950558 -284.521656)
		(width 0.088646)
		(layer "In4.Cu")
		(net "M_C_CPU0_SA_DQ<1>")
	)
	(segment
		(start 333.055722 -287.549336)
		(end 332.884526 -287.549336)
		(width 0.088646)
		(layer "In4.Cu")
		(net "M_C_CPU0_SA_DQ<1>")
	)
	(segment
		(start 339.954616 -278.336502)
		(end 339.612732 -278.626824)
		(width 0.088646)
		(layer "In4.Cu")
		(net "M_C_CPU0_SA_DQ<1>")
	)
	(segment
		(start 339.309456 -278.818848)
		(end 339.297264 -278.82596)
		(width 0.088646)
		(layer "In4.Cu")
		(net "M_C_CPU0_SA_DQ<1>")
	)
	(segment
		(start 320.998342 -306.848764)
		(end 314.45708 -313.390026)
		(width 0.18288)
		(layer "In4.Cu")
		(net "M_C_CPU0_SA_DQ<1>")
	)
	(segment
		(start 288.466784 -316.211712)
		(end 288.466784 -315.875416)
		(width 0.18288)
		(layer "In4.Cu")
		(net "M_C_CPU0_SA_DQ<1>")
	)
	(segment
		(start 336.290412 -285.661354)
		(end 336.290412 -285.679896)
		(width 0.088646)
		(layer "In4.Cu")
		(net "M_C_CPU0_SA_DQ<1>")
	)
	(segment
		(start 339.297264 -278.82596)
		(end 339.288374 -278.83104)
		(width 0.088646)
		(layer "In4.Cu")
		(net "M_C_CPU0_SA_DQ<1>")
	)
	(segment
		(start 336.947764 -284.52318)
		(end 336.938874 -284.52826)
		(width 0.088646)
		(layer "In4.Cu")
		(net "M_C_CPU0_SA_DQ<1>")
	)
	(segment
		(start 331.51953 -288.819844)
		(end 327.676002 -298.096178)
		(width 0.18288)
		(layer "In4.Cu")
		(net "M_C_CPU0_SA_DQ<1>")
	)
	(arc
		(start 338.640166 -283.219906)
		(mid 338.567931 -283.49643)
		(end 338.369656 -283.702252)
		(width 0.088646)
		(layer "In4.Cu")
		(net "M_C_CPU0_SA_DQ<1>")
	)
	(arc
		(start 336.760312 -284.857444)
		(mid 336.682201 -285.134393)
		(end 336.477864 -285.336996)
		(width 0.088646)
		(layer "In4.Cu")
		(net "M_C_CPU0_SA_DQ<1>")
	)
	(arc
		(start 338.83346 -281.919934)
		(mid 339.036047 -282.126285)
		(end 339.110066 -282.405836)
		(width 0.088646)
		(layer "In4.Cu")
		(net "M_C_CPU0_SA_DQ<1>")
	)
	(arc
		(start 336.007964 -286.151066)
		(mid 335.725262 -286.226808)
		(end 335.44256 -286.151066)
		(width 0.088646)
		(layer "In4.Cu")
		(net "M_C_CPU0_SA_DQ<1>")
	)
	(arc
		(start 333.940912 -286.48533)
		(mid 333.862801 -286.762279)
		(end 333.658464 -286.964882)
		(width 0.088646)
		(layer "In4.Cu")
		(net "M_C_CPU0_SA_DQ<1>")
	)
	(arc
		(start 337.79206 -283.709364)
		(mid 337.604862 -283.659221)
		(end 337.417664 -283.709364)
		(width 0.088646)
		(layer "In4.Cu")
		(net "M_C_CPU0_SA_DQ<1>")
	)
	(arc
		(start 336.468974 -285.342076)
		(mid 336.33806 -285.478436)
		(end 336.290412 -285.661354)
		(width 0.088646)
		(layer "In4.Cu")
		(net "M_C_CPU0_SA_DQ<1>")
	)
	(arc
		(start 334.50276 -286.151066)
		(mid 334.315562 -286.100923)
		(end 334.128364 -286.151066)
		(width 0.088646)
		(layer "In4.Cu")
		(net "M_C_CPU0_SA_DQ<1>")
	)
	(arc
		(start 339.430106 -278.720042)
		(mid 339.373201 -278.773621)
		(end 339.309456 -278.818848)
		(width 0.088646)
		(layer "In4.Cu")
		(net "M_C_CPU0_SA_DQ<1>")
	)
	(arc
		(start 334.119474 -286.156146)
		(mid 333.98856 -286.292506)
		(end 333.940912 -286.475424)
		(width 0.088646)
		(layer "In4.Cu")
		(net "M_C_CPU0_SA_DQ<1>")
	)
	(arc
		(start 335.068164 -286.151066)
		(mid 334.785462 -286.226808)
		(end 334.50276 -286.151066)
		(width 0.088646)
		(layer "In4.Cu")
		(net "M_C_CPU0_SA_DQ<1>")
	)
	(arc
		(start 336.290412 -285.679896)
		(mid 336.21025 -285.952085)
		(end 336.007964 -286.151066)
		(width 0.088646)
		(layer "In4.Cu")
		(net "M_C_CPU0_SA_DQ<1>")
	)
	(arc
		(start 335.44256 -286.151066)
		(mid 335.255362 -286.100923)
		(end 335.068164 -286.151066)
		(width 0.088646)
		(layer "In4.Cu")
		(net "M_C_CPU0_SA_DQ<1>")
	)
	(arc
		(start 336.938874 -284.52826)
		(mid 336.80796 -284.66462)
		(end 336.760312 -284.847538)
		(width 0.088646)
		(layer "In4.Cu")
		(net "M_C_CPU0_SA_DQ<1>")
	)
	(arc
		(start 339.109812 -280.793698)
		(mid 339.030442 -281.067432)
		(end 338.827618 -281.267662)
		(width 0.088646)
		(layer "In4.Cu")
		(net "M_C_CPU0_SA_DQ<1>")
	)
	(arc
		(start 339.579966 -279.978358)
		(mid 339.500747 -280.253043)
		(end 339.297264 -280.453846)
		(width 0.088646)
		(layer "In4.Cu")
		(net "M_C_CPU0_SA_DQ<1>")
	)
	(arc
		(start 338.818728 -282.900628)
		(mid 338.687814 -283.036988)
		(end 338.640166 -283.219906)
		(width 0.088646)
		(layer "In4.Cu")
		(net "M_C_CPU0_SA_DQ<1>")
	)
	(arc
		(start 338.818474 -281.272742)
		(mid 338.639877 -281.59202)
		(end 338.818474 -281.911298)
		(width 0.088646)
		(layer "In4.Cu")
		(net "M_C_CPU0_SA_DQ<1>")
	)
	(arc
		(start 333.658464 -286.964882)
		(mid 333.617655 -286.992054)
		(end 333.58074 -287.024318)
		(width 0.088646)
		(layer "In4.Cu")
		(net "M_C_CPU0_SA_DQ<1>")
	)
	(arc
		(start 339.110066 -282.42006)
		(mid 339.030847 -282.694745)
		(end 338.827364 -282.895548)
		(width 0.088646)
		(layer "In4.Cu")
		(net "M_C_CPU0_SA_DQ<1>")
	)
	(arc
		(start 339.288374 -280.458926)
		(mid 339.15746 -280.595286)
		(end 339.109812 -280.778204)
		(width 0.088646)
		(layer "In4.Cu")
		(net "M_C_CPU0_SA_DQ<1>")
	)
	(arc
		(start 339.288374 -278.83104)
		(mid 339.109777 -279.150318)
		(end 339.288374 -279.469596)
		(width 0.088646)
		(layer "In4.Cu")
		(net "M_C_CPU0_SA_DQ<1>")
	)
	(arc
		(start 337.230466 -284.033722)
		(mid 337.156475 -284.313288)
		(end 336.95386 -284.519624)
		(width 0.088646)
		(layer "In4.Cu")
		(net "M_C_CPU0_SA_DQ<1>")
	)
	(arc
		(start 339.30336 -279.478232)
		(mid 339.505947 -279.684583)
		(end 339.579966 -279.964134)
		(width 0.088646)
		(layer "In4.Cu")
		(net "M_C_CPU0_SA_DQ<1>")
	)
	(arc
		(start 338.357464 -283.709364)
		(mid 338.074762 -283.78514)
		(end 337.79206 -283.709364)
		(width 0.088646)
		(layer "In4.Cu")
		(net "M_C_CPU0_SA_DQ<1>")
	)
	(arc
		(start 337.417664 -283.709364)
		(mid 337.282731 -283.842718)
		(end 337.230466 -284.025086)
		(width 0.088646)
		(layer "In4.Cu")
		(net "M_C_CPU0_SA_DQ<1>")
	)
	(segment
		(start 281.788362 -295.274238)
		(end 281.34183 -295.274238)
		(width 0.20066)
		(layer "F.Cu")
		(net "M_C_CPU0_SA_DQ<19>")
	)
	(segment
		(start 277.091394 -295.363392)
		(end 277.091394 -295.192704)
		(width 0.20066)
		(layer "F.Cu")
		(net "M_C_CPU0_SA_DQ<19>")
	)
	(segment
		(start 277.233888 -295.505886)
		(end 277.091394 -295.363392)
		(width 0.20066)
		(layer "F.Cu")
		(net "M_C_CPU0_SA_DQ<19>")
	)
	(segment
		(start 279.912826 -295.491662)
		(end 277.839932 -295.491662)
		(width 0.1016)
		(layer "F.Cu")
		(net "M_C_CPU0_SA_DQ<19>")
	)
	(segment
		(start 277.58771 -295.505886)
		(end 277.233888 -295.505886)
		(width 0.20066)
		(layer "F.Cu")
		(net "M_C_CPU0_SA_DQ<19>")
	)
	(segment
		(start 280.606246 -295.342564)
		(end 280.457148 -295.491662)
		(width 0.20066)
		(layer "F.Cu")
		(net "M_C_CPU0_SA_DQ<19>")
	)
	(segment
		(start 282.811982 -295.06672)
		(end 281.99588 -295.06672)
		(width 0.20066)
		(layer "F.Cu")
		(net "M_C_CPU0_SA_DQ<19>")
	)
	(segment
		(start 281.34183 -295.274238)
		(end 281.129994 -295.062402)
		(width 0.20066)
		(layer "F.Cu")
		(net "M_C_CPU0_SA_DQ<19>")
	)
	(segment
		(start 281.99588 -295.06672)
		(end 281.788362 -295.274238)
		(width 0.20066)
		(layer "F.Cu")
		(net "M_C_CPU0_SA_DQ<19>")
	)
	(segment
		(start 280.457148 -295.491662)
		(end 279.912826 -295.491662)
		(width 0.20066)
		(layer "F.Cu")
		(net "M_C_CPU0_SA_DQ<19>")
	)
	(segment
		(start 283.916882 -295.06672)
		(end 282.811982 -295.06672)
		(width 0.20066)
		(layer "F.Cu")
		(net "M_C_CPU0_SA_DQ<19>")
	)
	(segment
		(start 281.129994 -295.062402)
		(end 280.73477 -295.062402)
		(width 0.20066)
		(layer "F.Cu")
		(net "M_C_CPU0_SA_DQ<19>")
	)
	(segment
		(start 277.091394 -295.192704)
		(end 276.96541 -295.06672)
		(width 0.20066)
		(layer "F.Cu")
		(net "M_C_CPU0_SA_DQ<19>")
	)
	(segment
		(start 277.839932 -295.491662)
		(end 277.601934 -295.491662)
		(width 0.101854)
		(layer "F.Cu")
		(net "M_C_CPU0_SA_DQ<19>")
	)
	(segment
		(start 341.834216 -268.034008)
		(end 341.834216 -268.569694)
		(width 0.20066)
		(layer "F.Cu")
		(net "M_C_CPU0_SA_DQ<19>")
	)
	(segment
		(start 341.833962 -268.033754)
		(end 341.834216 -268.034008)
		(width 0.20066)
		(layer "F.Cu")
		(net "M_C_CPU0_SA_DQ<19>")
	)
	(segment
		(start 280.73477 -295.062402)
		(end 280.606246 -295.190926)
		(width 0.20066)
		(layer "F.Cu")
		(net "M_C_CPU0_SA_DQ<19>")
	)
	(segment
		(start 280.606246 -295.190926)
		(end 280.606246 -295.342564)
		(width 0.20066)
		(layer "F.Cu")
		(net "M_C_CPU0_SA_DQ<19>")
	)
	(segment
		(start 276.96541 -295.06672)
		(end 275.268182 -295.06672)
		(width 0.20066)
		(layer "F.Cu")
		(net "M_C_CPU0_SA_DQ<19>")
	)
	(segment
		(start 277.601934 -295.491662)
		(end 277.58771 -295.505886)
		(width 0.101854)
		(layer "F.Cu")
		(net "M_C_CPU0_SA_DQ<19>")
	)
	(segment
		(start 312.472324 -290.51504)
		(end 311.083452 -290.51504)
		(width 0.18288)
		(layer "In4.Cu")
		(net "M_C_CPU0_SA_DQ<19>")
	)
	(segment
		(start 290.455604 -294.677084)
		(end 290.130484 -294.677084)
		(width 0.18288)
		(layer "In4.Cu")
		(net "M_C_CPU0_SA_DQ<19>")
	)
	(segment
		(start 289.947604 -294.859964)
		(end 289.947604 -295.275)
		(width 0.18288)
		(layer "In4.Cu")
		(net "M_C_CPU0_SA_DQ<19>")
	)
	(segment
		(start 313.140344 -289.987736)
		(end 312.792364 -289.987736)
		(width 0.18288)
		(layer "In4.Cu")
		(net "M_C_CPU0_SA_DQ<19>")
	)
	(segment
		(start 285.830772 -295.44645)
		(end 285.647892 -295.62933)
		(width 0.18288)
		(layer "In4.Cu")
		(net "M_C_CPU0_SA_DQ<19>")
	)
	(segment
		(start 287.614106 -295.62933)
		(end 286.704532 -295.62933)
		(width 0.18288)
		(layer "In4.Cu")
		(net "M_C_CPU0_SA_DQ<19>")
	)
	(segment
		(start 320.05016 -280.728928)
		(end 317.699898 -286.40278)
		(width 0.18288)
		(layer "In4.Cu")
		(net "M_C_CPU0_SA_DQ<19>")
	)
	(segment
		(start 287.785556 -295.45788)
		(end 287.614106 -295.62933)
		(width 0.18288)
		(layer "In4.Cu")
		(net "M_C_CPU0_SA_DQ<19>")
	)
	(segment
		(start 330.655168 -270.12392)
		(end 320.05016 -280.728928)
		(width 0.18288)
		(layer "In4.Cu")
		(net "M_C_CPU0_SA_DQ<19>")
	)
	(segment
		(start 341.096346 -268.253972)
		(end 341.081614 -268.245336)
		(width 0.088646)
		(layer "In4.Cu")
		(net "M_C_CPU0_SA_DQ<19>")
	)
	(segment
		(start 290.638484 -295.275)
		(end 290.638484 -294.859964)
		(width 0.18288)
		(layer "In4.Cu")
		(net "M_C_CPU0_SA_DQ<19>")
	)
	(segment
		(start 306.607972 -293.076122)
		(end 304.884836 -293.789862)
		(width 0.18288)
		(layer "In4.Cu")
		(net "M_C_CPU0_SA_DQ<19>")
	)
	(segment
		(start 289.947604 -295.275)
		(end 289.764724 -295.45788)
		(width 0.18288)
		(layer "In4.Cu")
		(net "M_C_CPU0_SA_DQ<19>")
	)
	(segment
		(start 312.632344 -290.147756)
		(end 312.632344 -290.35502)
		(width 0.18288)
		(layer "In4.Cu")
		(net "M_C_CPU0_SA_DQ<19>")
	)
	(segment
		(start 286.013652 -294.937688)
		(end 285.830772 -295.120568)
		(width 0.18288)
		(layer "In4.Cu")
		(net "M_C_CPU0_SA_DQ<19>")
	)
	(segment
		(start 307.678328 -293.076122)
		(end 306.607972 -293.076122)
		(width 0.18288)
		(layer "In4.Cu")
		(net "M_C_CPU0_SA_DQ<19>")
	)
	(segment
		(start 296.351198 -295.489376)
		(end 295.496996 -296.343578)
		(width 0.18288)
		(layer "In4.Cu")
		(net "M_C_CPU0_SA_DQ<19>")
	)
	(segment
		(start 285.830772 -295.120568)
		(end 285.830772 -295.44645)
		(width 0.18288)
		(layer "In4.Cu")
		(net "M_C_CPU0_SA_DQ<19>")
	)
	(segment
		(start 300.287436 -295.489376)
		(end 296.351198 -295.489376)
		(width 0.18288)
		(layer "In4.Cu")
		(net "M_C_CPU0_SA_DQ<19>")
	)
	(segment
		(start 336.947764 -268.894052)
		(end 336.941922 -268.89075)
		(width 0.088646)
		(layer "In4.Cu")
		(net "M_C_CPU0_SA_DQ<19>")
	)
	(segment
		(start 308.360826 -292.57879)
		(end 307.994304 -292.945312)
		(width 0.18288)
		(layer "In4.Cu")
		(net "M_C_CPU0_SA_DQ<19>")
	)
	(segment
		(start 288.565844 -294.859964)
		(end 288.565844 -295.275)
		(width 0.18288)
		(layer "In4.Cu")
		(net "M_C_CPU0_SA_DQ<19>")
	)
	(segment
		(start 339.670898 -268.31798)
		(end 339.617304 -268.371574)
		(width 0.088646)
		(layer "In4.Cu")
		(net "M_C_CPU0_SA_DQ<19>")
	)
	(segment
		(start 289.256724 -295.275)
		(end 289.256724 -294.859964)
		(width 0.18288)
		(layer "In4.Cu")
		(net "M_C_CPU0_SA_DQ<19>")
	)
	(segment
		(start 312.792364 -289.987736)
		(end 312.632344 -290.147756)
		(width 0.18288)
		(layer "In4.Cu")
		(net "M_C_CPU0_SA_DQ<19>")
	)
	(segment
		(start 337.891882 -268.896592)
		(end 337.887564 -268.894052)
		(width 0.088646)
		(layer "In4.Cu")
		(net "M_C_CPU0_SA_DQ<19>")
	)
	(segment
		(start 338.827364 -268.894052)
		(end 338.821522 -268.89075)
		(width 0.088646)
		(layer "In4.Cu")
		(net "M_C_CPU0_SA_DQ<19>")
	)
	(segment
		(start 285.647892 -295.62933)
		(end 284.479492 -295.62933)
		(width 0.18288)
		(layer "In4.Cu")
		(net "M_C_CPU0_SA_DQ<19>")
	)
	(segment
		(start 336.012282 -268.896592)
		(end 336.007964 -268.894052)
		(width 0.088646)
		(layer "In4.Cu")
		(net "M_C_CPU0_SA_DQ<19>")
	)
	(segment
		(start 339.773006 -268.242034)
		(end 339.761322 -268.248638)
		(width 0.088646)
		(layer "In4.Cu")
		(net "M_C_CPU0_SA_DQ<19>")
	)
	(segment
		(start 304.884836 -293.789862)
		(end 301.98695 -293.789862)
		(width 0.18288)
		(layer "In4.Cu")
		(net "M_C_CPU0_SA_DQ<19>")
	)
	(segment
		(start 317.699898 -286.40278)
		(end 314.668154 -289.434524)
		(width 0.18288)
		(layer "In4.Cu")
		(net "M_C_CPU0_SA_DQ<19>")
	)
	(segment
		(start 286.521652 -295.44645)
		(end 286.521652 -295.120568)
		(width 0.18288)
		(layer "In4.Cu")
		(net "M_C_CPU0_SA_DQ<19>")
	)
	(segment
		(start 332.313026 -269.260574)
		(end 331.44968 -270.12392)
		(width 0.088646)
		(layer "In4.Cu")
		(net "M_C_CPU0_SA_DQ<19>")
	)
	(segment
		(start 289.764724 -295.45788)
		(end 289.439604 -295.45788)
		(width 0.18288)
		(layer "In4.Cu")
		(net "M_C_CPU0_SA_DQ<19>")
	)
	(segment
		(start 311.083452 -290.51504)
		(end 310.287162 -291.31133)
		(width 0.18288)
		(layer "In4.Cu")
		(net "M_C_CPU0_SA_DQ<19>")
	)
	(segment
		(start 292.012116 -295.45788)
		(end 290.821364 -295.45788)
		(width 0.18288)
		(layer "In4.Cu")
		(net "M_C_CPU0_SA_DQ<19>")
	)
	(segment
		(start 301.98695 -293.789862)
		(end 300.287436 -295.489376)
		(width 0.18288)
		(layer "In4.Cu")
		(net "M_C_CPU0_SA_DQ<19>")
	)
	(segment
		(start 289.439604 -295.45788)
		(end 289.256724 -295.275)
		(width 0.18288)
		(layer "In4.Cu")
		(net "M_C_CPU0_SA_DQ<19>")
	)
	(segment
		(start 290.130484 -294.677084)
		(end 289.947604 -294.859964)
		(width 0.18288)
		(layer "In4.Cu")
		(net "M_C_CPU0_SA_DQ<19>")
	)
	(segment
		(start 286.521652 -295.120568)
		(end 286.338772 -294.937688)
		(width 0.18288)
		(layer "In4.Cu")
		(net "M_C_CPU0_SA_DQ<19>")
	)
	(segment
		(start 288.565844 -295.275)
		(end 288.382964 -295.45788)
		(width 0.18288)
		(layer "In4.Cu")
		(net "M_C_CPU0_SA_DQ<19>")
	)
	(segment
		(start 331.44968 -270.12392)
		(end 331.258672 -270.12392)
		(width 0.088646)
		(layer "In4.Cu")
		(net "M_C_CPU0_SA_DQ<19>")
	)
	(segment
		(start 289.073844 -294.677084)
		(end 288.748724 -294.677084)
		(width 0.18288)
		(layer "In4.Cu")
		(net "M_C_CPU0_SA_DQ<19>")
	)
	(segment
		(start 308.360826 -292.19271)
		(end 308.360826 -292.57879)
		(width 0.18288)
		(layer "In4.Cu")
		(net "M_C_CPU0_SA_DQ<19>")
	)
	(segment
		(start 307.994304 -292.945312)
		(end 307.678328 -293.076122)
		(width 0.18288)
		(layer "In4.Cu")
		(net "M_C_CPU0_SA_DQ<19>")
	)
	(segment
		(start 290.821364 -295.45788)
		(end 290.638484 -295.275)
		(width 0.18288)
		(layer "In4.Cu")
		(net "M_C_CPU0_SA_DQ<19>")
	)
	(segment
		(start 313.693556 -289.434524)
		(end 313.140344 -289.987736)
		(width 0.18288)
		(layer "In4.Cu")
		(net "M_C_CPU0_SA_DQ<19>")
	)
	(segment
		(start 331.258672 -270.12392)
		(end 330.655168 -270.12392)
		(width 0.18288)
		(layer "In4.Cu")
		(net "M_C_CPU0_SA_DQ<19>")
	)
	(segment
		(start 286.704532 -295.62933)
		(end 286.521652 -295.44645)
		(width 0.18288)
		(layer "In4.Cu")
		(net "M_C_CPU0_SA_DQ<19>")
	)
	(segment
		(start 314.668154 -289.434524)
		(end 313.693556 -289.434524)
		(width 0.18288)
		(layer "In4.Cu")
		(net "M_C_CPU0_SA_DQ<19>")
	)
	(segment
		(start 284.479492 -295.62933)
		(end 283.916882 -295.06672)
		(width 0.18288)
		(layer "In4.Cu")
		(net "M_C_CPU0_SA_DQ<19>")
	)
	(segment
		(start 295.496996 -296.343578)
		(end 292.897814 -296.343578)
		(width 0.18288)
		(layer "In4.Cu")
		(net "M_C_CPU0_SA_DQ<19>")
	)
	(segment
		(start 289.256724 -294.859964)
		(end 289.073844 -294.677084)
		(width 0.18288)
		(layer "In4.Cu")
		(net "M_C_CPU0_SA_DQ<19>")
	)
	(segment
		(start 286.338772 -294.937688)
		(end 286.013652 -294.937688)
		(width 0.18288)
		(layer "In4.Cu")
		(net "M_C_CPU0_SA_DQ<19>")
	)
	(segment
		(start 336.951574 -268.896338)
		(end 336.947764 -268.894052)
		(width 0.088646)
		(layer "In4.Cu")
		(net "M_C_CPU0_SA_DQ<19>")
	)
	(segment
		(start 310.287162 -291.31133)
		(end 309.242206 -291.31133)
		(width 0.18288)
		(layer "In4.Cu")
		(net "M_C_CPU0_SA_DQ<19>")
	)
	(segment
		(start 292.897814 -296.343578)
		(end 292.012116 -295.45788)
		(width 0.18288)
		(layer "In4.Cu")
		(net "M_C_CPU0_SA_DQ<19>")
	)
	(segment
		(start 338.833206 -268.897608)
		(end 338.827364 -268.894052)
		(width 0.088646)
		(layer "In4.Cu")
		(net "M_C_CPU0_SA_DQ<19>")
	)
	(segment
		(start 288.748724 -294.677084)
		(end 288.565844 -294.859964)
		(width 0.18288)
		(layer "In4.Cu")
		(net "M_C_CPU0_SA_DQ<19>")
	)
	(segment
		(start 309.242206 -291.31133)
		(end 308.360826 -292.19271)
		(width 0.18288)
		(layer "In4.Cu")
		(net "M_C_CPU0_SA_DQ<19>")
	)
	(segment
		(start 290.638484 -294.859964)
		(end 290.455604 -294.677084)
		(width 0.18288)
		(layer "In4.Cu")
		(net "M_C_CPU0_SA_DQ<19>")
	)
	(segment
		(start 288.382964 -295.45788)
		(end 287.785556 -295.45788)
		(width 0.18288)
		(layer "In4.Cu")
		(net "M_C_CPU0_SA_DQ<19>")
	)
	(segment
		(start 312.632344 -290.35502)
		(end 312.472324 -290.51504)
		(width 0.18288)
		(layer "In4.Cu")
		(net "M_C_CPU0_SA_DQ<19>")
	)
	(arc
		(start 339.476842 -268.581124)
		(mid 339.365151 -268.760179)
		(end 339.202014 -268.894052)
		(width 0.088646)
		(layer "In4.Cu")
		(net "M_C_CPU0_SA_DQ<19>")
	)
	(arc
		(start 337.887564 -268.894052)
		(mid 337.605006 -268.818403)
		(end 337.322414 -268.894052)
		(width 0.088646)
		(layer "In4.Cu")
		(net "M_C_CPU0_SA_DQ<19>")
	)
	(arc
		(start 341.081614 -268.245336)
		(mid 340.894416 -268.195193)
		(end 340.707218 -268.245336)
		(width 0.088646)
		(layer "In4.Cu")
		(net "M_C_CPU0_SA_DQ<19>")
	)
	(arc
		(start 338.262214 -268.894052)
		(mid 338.077377 -268.944313)
		(end 337.891882 -268.896592)
		(width 0.088646)
		(layer "In4.Cu")
		(net "M_C_CPU0_SA_DQ<19>")
	)
	(arc
		(start 339.617304 -268.371574)
		(mid 339.536812 -268.469472)
		(end 339.476842 -268.581124)
		(width 0.088646)
		(layer "In4.Cu")
		(net "M_C_CPU0_SA_DQ<19>")
	)
	(arc
		(start 339.202014 -268.894052)
		(mid 339.01809 -268.944306)
		(end 338.833206 -268.897608)
		(width 0.088646)
		(layer "In4.Cu")
		(net "M_C_CPU0_SA_DQ<19>")
	)
	(arc
		(start 337.322414 -268.894052)
		(mid 337.137293 -268.944315)
		(end 336.951574 -268.896338)
		(width 0.088646)
		(layer "In4.Cu")
		(net "M_C_CPU0_SA_DQ<19>")
	)
	(arc
		(start 339.761322 -268.248638)
		(mid 339.71383 -268.280336)
		(end 339.670898 -268.31798)
		(width 0.088646)
		(layer "In4.Cu")
		(net "M_C_CPU0_SA_DQ<19>")
	)
	(arc
		(start 334.128364 -268.894052)
		(mid 333.845662 -268.818276)
		(end 333.56296 -268.894052)
		(width 0.088646)
		(layer "In4.Cu")
		(net "M_C_CPU0_SA_DQ<19>")
	)
	(arc
		(start 334.50276 -268.894052)
		(mid 334.315562 -268.944195)
		(end 334.128364 -268.894052)
		(width 0.088646)
		(layer "In4.Cu")
		(net "M_C_CPU0_SA_DQ<19>")
	)
	(arc
		(start 336.941922 -268.89075)
		(mid 336.661817 -268.818308)
		(end 336.382614 -268.894052)
		(width 0.088646)
		(layer "In4.Cu")
		(net "M_C_CPU0_SA_DQ<19>")
	)
	(arc
		(start 332.521306 -269.174214)
		(mid 332.408566 -269.196657)
		(end 332.313026 -269.260574)
		(width 0.088646)
		(layer "In4.Cu")
		(net "M_C_CPU0_SA_DQ<19>")
	)
	(arc
		(start 336.007964 -268.894052)
		(mid 335.725262 -268.818276)
		(end 335.44256 -268.894052)
		(width 0.088646)
		(layer "In4.Cu")
		(net "M_C_CPU0_SA_DQ<19>")
	)
	(arc
		(start 338.821522 -268.89075)
		(mid 338.541417 -268.818308)
		(end 338.262214 -268.894052)
		(width 0.088646)
		(layer "In4.Cu")
		(net "M_C_CPU0_SA_DQ<19>")
	)
	(arc
		(start 340.707218 -268.245336)
		(mid 340.424516 -268.321078)
		(end 340.141814 -268.245336)
		(width 0.088646)
		(layer "In4.Cu")
		(net "M_C_CPU0_SA_DQ<19>")
	)
	(arc
		(start 333.56296 -268.894052)
		(mid 333.060635 -269.102909)
		(end 332.521306 -269.174214)
		(width 0.088646)
		(layer "In4.Cu")
		(net "M_C_CPU0_SA_DQ<19>")
	)
	(arc
		(start 335.068164 -268.894052)
		(mid 334.785462 -268.818276)
		(end 334.50276 -268.894052)
		(width 0.088646)
		(layer "In4.Cu")
		(net "M_C_CPU0_SA_DQ<19>")
	)
	(arc
		(start 335.44256 -268.894052)
		(mid 335.255362 -268.944195)
		(end 335.068164 -268.894052)
		(width 0.088646)
		(layer "In4.Cu")
		(net "M_C_CPU0_SA_DQ<19>")
	)
	(arc
		(start 336.382614 -268.894052)
		(mid 336.197777 -268.944313)
		(end 336.012282 -268.896592)
		(width 0.088646)
		(layer "In4.Cu")
		(net "M_C_CPU0_SA_DQ<19>")
	)
	(arc
		(start 340.141814 -268.245336)
		(mid 339.95786 -268.195207)
		(end 339.773006 -268.242034)
		(width 0.088646)
		(layer "In4.Cu")
		(net "M_C_CPU0_SA_DQ<19>")
	)
	(arc
		(start 341.834216 -268.569694)
		(mid 341.455335 -268.43508)
		(end 341.096346 -268.253972)
		(width 0.088646)
		(layer "In4.Cu")
		(net "M_C_CPU0_SA_DQ<19>")
	)
	(segment
		(start 280.689558 -296.811192)
		(end 280.689558 -296.485564)
		(width 0.20066)
		(layer "F.Cu")
		(net "M_C_CPU0_SA_DQ<18>")
	)
	(segment
		(start 282.811982 -296.766742)
		(end 281.497278 -296.766742)
		(width 0.20066)
		(layer "F.Cu")
		(net "M_C_CPU0_SA_DQ<18>")
	)
	(segment
		(start 281.497278 -296.766742)
		(end 281.285442 -296.978578)
		(width 0.20066)
		(layer "F.Cu")
		(net "M_C_CPU0_SA_DQ<18>")
	)
	(segment
		(start 283.916882 -296.766742)
		(end 282.811982 -296.766742)
		(width 0.20066)
		(layer "F.Cu")
		(net "M_C_CPU0_SA_DQ<18>")
	)
	(segment
		(start 276.415246 -296.766742)
		(end 275.268182 -296.766742)
		(width 0.20066)
		(layer "F.Cu")
		(net "M_C_CPU0_SA_DQ<18>")
	)
	(segment
		(start 280.856944 -296.978578)
		(end 280.689558 -296.811192)
		(width 0.20066)
		(layer "F.Cu")
		(net "M_C_CPU0_SA_DQ<18>")
	)
	(segment
		(start 341.364316 -268.84757)
		(end 341.364062 -268.847824)
		(width 0.20066)
		(layer "F.Cu")
		(net "M_C_CPU0_SA_DQ<18>")
	)
	(segment
		(start 341.364062 -268.847824)
		(end 341.364062 -269.38351)
		(width 0.20066)
		(layer "F.Cu")
		(net "M_C_CPU0_SA_DQ<18>")
	)
	(segment
		(start 277.59787 -296.3418)
		(end 277.58771 -296.33164)
		(width 0.101854)
		(layer "F.Cu")
		(net "M_C_CPU0_SA_DQ<18>")
	)
	(segment
		(start 276.850348 -296.33164)
		(end 276.415246 -296.766742)
		(width 0.20066)
		(layer "F.Cu")
		(net "M_C_CPU0_SA_DQ<18>")
	)
	(segment
		(start 277.58771 -296.33164)
		(end 276.850348 -296.33164)
		(width 0.20066)
		(layer "F.Cu")
		(net "M_C_CPU0_SA_DQ<18>")
	)
	(segment
		(start 277.852886 -296.3418)
		(end 277.59787 -296.3418)
		(width 0.101854)
		(layer "F.Cu")
		(net "M_C_CPU0_SA_DQ<18>")
	)
	(segment
		(start 280.545794 -296.3418)
		(end 279.912826 -296.3418)
		(width 0.20066)
		(layer "F.Cu")
		(net "M_C_CPU0_SA_DQ<18>")
	)
	(segment
		(start 280.689558 -296.485564)
		(end 280.545794 -296.3418)
		(width 0.20066)
		(layer "F.Cu")
		(net "M_C_CPU0_SA_DQ<18>")
	)
	(segment
		(start 279.912826 -296.3418)
		(end 277.852886 -296.3418)
		(width 0.1016)
		(layer "F.Cu")
		(net "M_C_CPU0_SA_DQ<18>")
	)
	(segment
		(start 281.285442 -296.978578)
		(end 280.856944 -296.978578)
		(width 0.20066)
		(layer "F.Cu")
		(net "M_C_CPU0_SA_DQ<18>")
	)
	(segment
		(start 298.276772 -297.189144)
		(end 298.093892 -297.372024)
		(width 0.18288)
		(layer "In4.Cu")
		(net "M_C_CPU0_SA_DQ<18>")
	)
	(segment
		(start 306.49291 -294.72509)
		(end 305.576986 -294.72509)
		(width 0.18288)
		(layer "In4.Cu")
		(net "M_C_CPU0_SA_DQ<18>")
	)
	(segment
		(start 307.547518 -294.10279)
		(end 307.158136 -294.26408)
		(width 0.18288)
		(layer "In4.Cu")
		(net "M_C_CPU0_SA_DQ<18>")
	)
	(segment
		(start 296.401998 -297.189144)
		(end 295.549828 -298.041314)
		(width 0.18288)
		(layer "In4.Cu")
		(net "M_C_CPU0_SA_DQ<18>")
	)
	(segment
		(start 291.4904 -296.981626)
		(end 288.446972 -296.981626)
		(width 0.18288)
		(layer "In4.Cu")
		(net "M_C_CPU0_SA_DQ<18>")
	)
	(segment
		(start 333.505048 -269.573248)
		(end 332.575916 -269.573248)
		(width 0.088646)
		(layer "In4.Cu")
		(net "M_C_CPU0_SA_DQ<18>")
	)
	(segment
		(start 304.809144 -295.492932)
		(end 302.197008 -295.492932)
		(width 0.18288)
		(layer "In4.Cu")
		(net "M_C_CPU0_SA_DQ<18>")
	)
	(segment
		(start 288.106612 -297.321986)
		(end 287.2105 -297.321986)
		(width 0.18288)
		(layer "In4.Cu")
		(net "M_C_CPU0_SA_DQ<18>")
	)
	(segment
		(start 311.153556 -292.133528)
		(end 310.498744 -292.78834)
		(width 0.18288)
		(layer "In4.Cu")
		(net "M_C_CPU0_SA_DQ<18>")
	)
	(segment
		(start 293.22014 -298.19346)
		(end 293.22014 -297.886374)
		(width 0.18288)
		(layer "In4.Cu")
		(net "M_C_CPU0_SA_DQ<18>")
	)
	(segment
		(start 314.051696 -291.032692)
		(end 312.95086 -292.133528)
		(width 0.18288)
		(layer "In4.Cu")
		(net "M_C_CPU0_SA_DQ<18>")
	)
	(segment
		(start 331.258672 -271.1196)
		(end 331.067918 -271.1196)
		(width 0.18288)
		(layer "In4.Cu")
		(net "M_C_CPU0_SA_DQ<18>")
	)
	(segment
		(start 293.03726 -297.703494)
		(end 292.212268 -297.703494)
		(width 0.18288)
		(layer "In4.Cu")
		(net "M_C_CPU0_SA_DQ<18>")
	)
	(segment
		(start 298.093892 -297.372024)
		(end 298.093892 -297.742356)
		(width 0.18288)
		(layer "In4.Cu")
		(net "M_C_CPU0_SA_DQ<18>")
	)
	(segment
		(start 339.859112 -269.38351)
		(end 339.859112 -269.392146)
		(width 0.088646)
		(layer "In4.Cu")
		(net "M_C_CPU0_SA_DQ<18>")
	)
	(segment
		(start 305.576986 -294.72509)
		(end 304.809144 -295.492932)
		(width 0.18288)
		(layer "In4.Cu")
		(net "M_C_CPU0_SA_DQ<18>")
	)
	(segment
		(start 294.613584 -298.041314)
		(end 294.416734 -297.844464)
		(width 0.18288)
		(layer "In4.Cu")
		(net "M_C_CPU0_SA_DQ<18>")
	)
	(segment
		(start 287.2105 -297.321986)
		(end 286.89554 -297.007026)
		(width 0.18288)
		(layer "In4.Cu")
		(net "M_C_CPU0_SA_DQ<18>")
	)
	(segment
		(start 332.352904 -270.296132)
		(end 331.529436 -271.1196)
		(width 0.088646)
		(layer "In4.Cu")
		(net "M_C_CPU0_SA_DQ<18>")
	)
	(segment
		(start 340.141814 -268.894052)
		(end 340.135718 -268.897608)
		(width 0.088646)
		(layer "In4.Cu")
		(net "M_C_CPU0_SA_DQ<18>")
	)
	(segment
		(start 312.95086 -292.133528)
		(end 311.153556 -292.133528)
		(width 0.18288)
		(layer "In4.Cu")
		(net "M_C_CPU0_SA_DQ<18>")
	)
	(segment
		(start 297.403012 -297.742356)
		(end 297.403012 -297.372024)
		(width 0.18288)
		(layer "In4.Cu")
		(net "M_C_CPU0_SA_DQ<18>")
	)
	(segment
		(start 339.297518 -269.707868)
		(end 339.287104 -269.701772)
		(width 0.088646)
		(layer "In4.Cu")
		(net "M_C_CPU0_SA_DQ<18>")
	)
	(segment
		(start 314.768738 -291.032692)
		(end 314.051696 -291.032692)
		(width 0.18288)
		(layer "In4.Cu")
		(net "M_C_CPU0_SA_DQ<18>")
	)
	(segment
		(start 298.093892 -297.742356)
		(end 297.911012 -297.925236)
		(width 0.18288)
		(layer "In4.Cu")
		(net "M_C_CPU0_SA_DQ<18>")
	)
	(segment
		(start 333.580486 -269.648686)
		(end 333.505048 -269.573248)
		(width 0.088646)
		(layer "In4.Cu")
		(net "M_C_CPU0_SA_DQ<18>")
	)
	(segment
		(start 297.403012 -297.372024)
		(end 297.220132 -297.189144)
		(width 0.18288)
		(layer "In4.Cu")
		(net "M_C_CPU0_SA_DQ<18>")
	)
	(segment
		(start 310.498744 -292.78834)
		(end 308.976268 -293.418768)
		(width 0.18288)
		(layer "In4.Cu")
		(net "M_C_CPU0_SA_DQ<18>")
	)
	(segment
		(start 293.91102 -298.027344)
		(end 293.91102 -298.19346)
		(width 0.18288)
		(layer "In4.Cu")
		(net "M_C_CPU0_SA_DQ<18>")
	)
	(segment
		(start 332.575916 -269.573248)
		(end 332.352904 -269.79626)
		(width 0.088646)
		(layer "In4.Cu")
		(net "M_C_CPU0_SA_DQ<18>")
	)
	(segment
		(start 320.957956 -281.229562)
		(end 318.402208 -287.399222)
		(width 0.18288)
		(layer "In4.Cu")
		(net "M_C_CPU0_SA_DQ<18>")
	)
	(segment
		(start 294.416734 -297.844464)
		(end 294.0939 -297.844464)
		(width 0.18288)
		(layer "In4.Cu")
		(net "M_C_CPU0_SA_DQ<18>")
	)
	(segment
		(start 288.446972 -296.981626)
		(end 288.106612 -297.321986)
		(width 0.18288)
		(layer "In4.Cu")
		(net "M_C_CPU0_SA_DQ<18>")
	)
	(segment
		(start 297.911012 -297.925236)
		(end 297.585892 -297.925236)
		(width 0.18288)
		(layer "In4.Cu")
		(net "M_C_CPU0_SA_DQ<18>")
	)
	(segment
		(start 308.072028 -294.10279)
		(end 307.547518 -294.10279)
		(width 0.18288)
		(layer "In4.Cu")
		(net "M_C_CPU0_SA_DQ<18>")
	)
	(segment
		(start 318.402208 -287.399222)
		(end 314.768738 -291.032692)
		(width 0.18288)
		(layer "In4.Cu")
		(net "M_C_CPU0_SA_DQ<18>")
	)
	(segment
		(start 340.156546 -268.885416)
		(end 340.141814 -268.894052)
		(width 0.088646)
		(layer "In4.Cu")
		(net "M_C_CPU0_SA_DQ<18>")
	)
	(segment
		(start 286.371792 -297.007026)
		(end 286.158178 -297.22064)
		(width 0.18288)
		(layer "In4.Cu")
		(net "M_C_CPU0_SA_DQ<18>")
	)
	(segment
		(start 300.500796 -297.189144)
		(end 298.276772 -297.189144)
		(width 0.18288)
		(layer "In4.Cu")
		(net "M_C_CPU0_SA_DQ<18>")
	)
	(segment
		(start 293.72814 -298.37634)
		(end 293.40302 -298.37634)
		(width 0.18288)
		(layer "In4.Cu")
		(net "M_C_CPU0_SA_DQ<18>")
	)
	(segment
		(start 293.22014 -297.886374)
		(end 293.03726 -297.703494)
		(width 0.18288)
		(layer "In4.Cu")
		(net "M_C_CPU0_SA_DQ<18>")
	)
	(segment
		(start 308.976268 -293.418768)
		(end 308.447694 -293.947342)
		(width 0.18288)
		(layer "In4.Cu")
		(net "M_C_CPU0_SA_DQ<18>")
	)
	(segment
		(start 292.212268 -297.703494)
		(end 291.4904 -296.981626)
		(width 0.18288)
		(layer "In4.Cu")
		(net "M_C_CPU0_SA_DQ<18>")
	)
	(segment
		(start 297.585892 -297.925236)
		(end 297.403012 -297.742356)
		(width 0.18288)
		(layer "In4.Cu")
		(net "M_C_CPU0_SA_DQ<18>")
	)
	(segment
		(start 286.158178 -297.22064)
		(end 284.37078 -297.22064)
		(width 0.18288)
		(layer "In4.Cu")
		(net "M_C_CPU0_SA_DQ<18>")
	)
	(segment
		(start 293.91102 -298.19346)
		(end 293.72814 -298.37634)
		(width 0.18288)
		(layer "In4.Cu")
		(net "M_C_CPU0_SA_DQ<18>")
	)
	(segment
		(start 332.352904 -269.79626)
		(end 332.352904 -270.296132)
		(width 0.088646)
		(layer "In4.Cu")
		(net "M_C_CPU0_SA_DQ<18>")
	)
	(segment
		(start 297.220132 -297.189144)
		(end 296.401998 -297.189144)
		(width 0.18288)
		(layer "In4.Cu")
		(net "M_C_CPU0_SA_DQ<18>")
	)
	(segment
		(start 286.89554 -297.007026)
		(end 286.371792 -297.007026)
		(width 0.18288)
		(layer "In4.Cu")
		(net "M_C_CPU0_SA_DQ<18>")
	)
	(segment
		(start 341.051388 -269.38351)
		(end 340.985856 -269.317978)
		(width 0.088646)
		(layer "In4.Cu")
		(net "M_C_CPU0_SA_DQ<18>")
	)
	(segment
		(start 331.529436 -271.1196)
		(end 331.258672 -271.1196)
		(width 0.088646)
		(layer "In4.Cu")
		(net "M_C_CPU0_SA_DQ<18>")
	)
	(segment
		(start 293.40302 -298.37634)
		(end 293.22014 -298.19346)
		(width 0.18288)
		(layer "In4.Cu")
		(net "M_C_CPU0_SA_DQ<18>")
	)
	(segment
		(start 341.364062 -269.38351)
		(end 341.051388 -269.38351)
		(width 0.088646)
		(layer "In4.Cu")
		(net "M_C_CPU0_SA_DQ<18>")
	)
	(segment
		(start 295.549828 -298.041314)
		(end 294.613584 -298.041314)
		(width 0.18288)
		(layer "In4.Cu")
		(net "M_C_CPU0_SA_DQ<18>")
	)
	(segment
		(start 302.197008 -295.492932)
		(end 300.500796 -297.189144)
		(width 0.18288)
		(layer "In4.Cu")
		(net "M_C_CPU0_SA_DQ<18>")
	)
	(segment
		(start 307.158136 -294.26408)
		(end 306.841398 -294.580818)
		(width 0.18288)
		(layer "In4.Cu")
		(net "M_C_CPU0_SA_DQ<18>")
	)
	(segment
		(start 284.37078 -297.22064)
		(end 283.916882 -296.766742)
		(width 0.18288)
		(layer "In4.Cu")
		(net "M_C_CPU0_SA_DQ<18>")
	)
	(segment
		(start 306.841398 -294.580818)
		(end 306.49291 -294.72509)
		(width 0.18288)
		(layer "In4.Cu")
		(net "M_C_CPU0_SA_DQ<18>")
	)
	(segment
		(start 331.067918 -271.1196)
		(end 320.957956 -281.229562)
		(width 0.18288)
		(layer "In4.Cu")
		(net "M_C_CPU0_SA_DQ<18>")
	)
	(segment
		(start 294.0939 -297.844464)
		(end 293.91102 -298.027344)
		(width 0.18288)
		(layer "In4.Cu")
		(net "M_C_CPU0_SA_DQ<18>")
	)
	(segment
		(start 308.447694 -293.947342)
		(end 308.072028 -294.10279)
		(width 0.18288)
		(layer "In4.Cu")
		(net "M_C_CPU0_SA_DQ<18>")
	)
	(arc
		(start 334.97266 -269.707868)
		(mid 334.785462 -269.758011)
		(end 334.598264 -269.707868)
		(width 0.088646)
		(layer "In4.Cu")
		(net "M_C_CPU0_SA_DQ<18>")
	)
	(arc
		(start 339.671914 -269.707868)
		(mid 339.484716 -269.758011)
		(end 339.297518 -269.707868)
		(width 0.088646)
		(layer "In4.Cu")
		(net "M_C_CPU0_SA_DQ<18>")
	)
	(arc
		(start 339.859112 -269.392146)
		(mid 339.806842 -269.574511)
		(end 339.671914 -269.707868)
		(width 0.088646)
		(layer "In4.Cu")
		(net "M_C_CPU0_SA_DQ<18>")
	)
	(arc
		(start 334.598264 -269.707868)
		(mid 334.315562 -269.632126)
		(end 334.03286 -269.707868)
		(width 0.088646)
		(layer "In4.Cu")
		(net "M_C_CPU0_SA_DQ<18>")
	)
	(arc
		(start 337.417664 -269.707868)
		(mid 337.134962 -269.632126)
		(end 336.85226 -269.707868)
		(width 0.088646)
		(layer "In4.Cu")
		(net "M_C_CPU0_SA_DQ<18>")
	)
	(arc
		(start 337.79206 -269.707868)
		(mid 337.604862 -269.758011)
		(end 337.417664 -269.707868)
		(width 0.088646)
		(layer "In4.Cu")
		(net "M_C_CPU0_SA_DQ<18>")
	)
	(arc
		(start 333.658464 -269.707868)
		(mid 333.617534 -269.680835)
		(end 333.580486 -269.648686)
		(width 0.088646)
		(layer "In4.Cu")
		(net "M_C_CPU0_SA_DQ<18>")
	)
	(arc
		(start 334.03286 -269.707868)
		(mid 333.845662 -269.758011)
		(end 333.658464 -269.707868)
		(width 0.088646)
		(layer "In4.Cu")
		(net "M_C_CPU0_SA_DQ<18>")
	)
	(arc
		(start 336.85226 -269.707868)
		(mid 336.665062 -269.758011)
		(end 336.477864 -269.707868)
		(width 0.088646)
		(layer "In4.Cu")
		(net "M_C_CPU0_SA_DQ<18>")
	)
	(arc
		(start 338.357464 -269.707868)
		(mid 338.074762 -269.632126)
		(end 337.79206 -269.707868)
		(width 0.088646)
		(layer "In4.Cu")
		(net "M_C_CPU0_SA_DQ<18>")
	)
	(arc
		(start 335.91246 -269.707868)
		(mid 335.725262 -269.758011)
		(end 335.538064 -269.707868)
		(width 0.088646)
		(layer "In4.Cu")
		(net "M_C_CPU0_SA_DQ<18>")
	)
	(arc
		(start 338.73186 -269.707868)
		(mid 338.544662 -269.758011)
		(end 338.357464 -269.707868)
		(width 0.088646)
		(layer "In4.Cu")
		(net "M_C_CPU0_SA_DQ<18>")
	)
	(arc
		(start 340.135718 -268.897608)
		(mid 339.933131 -269.103959)
		(end 339.859112 -269.38351)
		(width 0.088646)
		(layer "In4.Cu")
		(net "M_C_CPU0_SA_DQ<18>")
	)
	(arc
		(start 335.538064 -269.707868)
		(mid 335.255362 -269.632126)
		(end 334.97266 -269.707868)
		(width 0.088646)
		(layer "In4.Cu")
		(net "M_C_CPU0_SA_DQ<18>")
	)
	(arc
		(start 340.707218 -268.894052)
		(mid 340.433019 -268.818217)
		(end 340.156546 -268.885416)
		(width 0.088646)
		(layer "In4.Cu")
		(net "M_C_CPU0_SA_DQ<18>")
	)
	(arc
		(start 336.477864 -269.707868)
		(mid 336.195162 -269.632126)
		(end 335.91246 -269.707868)
		(width 0.088646)
		(layer "In4.Cu")
		(net "M_C_CPU0_SA_DQ<18>")
	)
	(arc
		(start 340.985856 -269.317978)
		(mid 340.896768 -269.072993)
		(end 340.707218 -268.894052)
		(width 0.088646)
		(layer "In4.Cu")
		(net "M_C_CPU0_SA_DQ<18>")
	)
	(arc
		(start 339.287104 -269.701772)
		(mid 339.008672 -269.631958)
		(end 338.73186 -269.707868)
		(width 0.088646)
		(layer "In4.Cu")
		(net "M_C_CPU0_SA_DQ<18>")
	)
	(segment
		(start 277.072598 -295.916604)
		(end 276.647656 -295.491662)
		(width 0.20066)
		(layer "F.Cu")
		(net "M_C_CPU0_SA_DQ<17>")
	)
	(segment
		(start 272.713704 -296.127932)
		(end 272.502376 -295.916604)
		(width 0.20066)
		(layer "F.Cu")
		(net "M_C_CPU0_SA_DQ<17>")
	)
	(segment
		(start 273.53514 -295.482772)
		(end 273.37258 -295.645332)
		(width 0.20066)
		(layer "F.Cu")
		(net "M_C_CPU0_SA_DQ<17>")
	)
	(segment
		(start 278.711914 -295.916604)
		(end 277.072598 -295.916604)
		(width 0.20066)
		(layer "F.Cu")
		(net "M_C_CPU0_SA_DQ<17>")
	)
	(segment
		(start 274.143978 -295.482772)
		(end 273.53514 -295.482772)
		(width 0.20066)
		(layer "F.Cu")
		(net "M_C_CPU0_SA_DQ<17>")
	)
	(segment
		(start 276.469094 -295.491662)
		(end 276.138386 -295.491662)
		(width 0.101854)
		(layer "F.Cu")
		(net "M_C_CPU0_SA_DQ<17>")
	)
	(segment
		(start 274.152868 -295.491662)
		(end 274.143978 -295.482772)
		(width 0.1016)
		(layer "F.Cu")
		(net "M_C_CPU0_SA_DQ<17>")
	)
	(segment
		(start 279.816814 -295.916604)
		(end 278.711914 -295.916604)
		(width 0.20066)
		(layer "F.Cu")
		(net "M_C_CPU0_SA_DQ<17>")
	)
	(segment
		(start 273.218148 -296.127932)
		(end 272.713704 -296.127932)
		(width 0.20066)
		(layer "F.Cu")
		(net "M_C_CPU0_SA_DQ<17>")
	)
	(segment
		(start 273.37258 -295.9735)
		(end 273.218148 -296.127932)
		(width 0.20066)
		(layer "F.Cu")
		(net "M_C_CPU0_SA_DQ<17>")
	)
	(segment
		(start 272.502376 -295.916604)
		(end 271.168114 -295.916604)
		(width 0.20066)
		(layer "F.Cu")
		(net "M_C_CPU0_SA_DQ<17>")
	)
	(segment
		(start 273.37258 -295.645332)
		(end 273.37258 -295.9735)
		(width 0.20066)
		(layer "F.Cu")
		(net "M_C_CPU0_SA_DQ<17>")
	)
	(segment
		(start 339.954616 -268.034008)
		(end 339.954616 -268.569694)
		(width 0.20066)
		(layer "F.Cu")
		(net "M_C_CPU0_SA_DQ<17>")
	)
	(segment
		(start 276.138386 -295.491662)
		(end 274.152868 -295.491662)
		(width 0.1016)
		(layer "F.Cu")
		(net "M_C_CPU0_SA_DQ<17>")
	)
	(segment
		(start 276.647656 -295.491662)
		(end 276.469094 -295.491662)
		(width 0.20066)
		(layer "F.Cu")
		(net "M_C_CPU0_SA_DQ<17>")
	)
	(segment
		(start 339.954362 -268.033754)
		(end 339.954616 -268.034008)
		(width 0.20066)
		(layer "F.Cu")
		(net "M_C_CPU0_SA_DQ<17>")
	)
	(segment
		(start 331.569822 -270.62176)
		(end 331.258672 -270.62176)
		(width 0.088646)
		(layer "In4.Cu")
		(net "M_C_CPU0_SA_DQ<17>")
	)
	(segment
		(start 308.240938 -293.417752)
		(end 307.840126 -293.583868)
		(width 0.18288)
		(layer "In4.Cu")
		(net "M_C_CPU0_SA_DQ<17>")
	)
	(segment
		(start 291.570664 -296.342054)
		(end 284.22092 -296.342054)
		(width 0.18288)
		(layer "In4.Cu")
		(net "M_C_CPU0_SA_DQ<17>")
	)
	(segment
		(start 338.737956 -269.062708)
		(end 338.732114 -269.059152)
		(width 0.088646)
		(layer "In4.Cu")
		(net "M_C_CPU0_SA_DQ<17>")
	)
	(segment
		(start 338.732114 -269.059152)
		(end 338.726272 -269.05585)
		(width 0.088646)
		(layer "In4.Cu")
		(net "M_C_CPU0_SA_DQ<17>")
	)
	(segment
		(start 284.220666 -296.3418)
		(end 283.71927 -296.3418)
		(width 0.18288)
		(layer "In4.Cu")
		(net "M_C_CPU0_SA_DQ<17>")
	)
	(segment
		(start 299.7962 -296.339514)
		(end 298.499022 -296.339514)
		(width 0.18288)
		(layer "In4.Cu")
		(net "M_C_CPU0_SA_DQ<17>")
	)
	(segment
		(start 305.220878 -294.244522)
		(end 304.681636 -294.783764)
		(width 0.18288)
		(layer "In4.Cu")
		(net "M_C_CPU0_SA_DQ<17>")
	)
	(segment
		(start 303.14138 -294.499792)
		(end 302.018192 -294.499792)
		(width 0.18288)
		(layer "In4.Cu")
		(net "M_C_CPU0_SA_DQ<17>")
	)
	(segment
		(start 320.484246 -280.999184)
		(end 318.013588 -286.963358)
		(width 0.18288)
		(layer "In4.Cu")
		(net "M_C_CPU0_SA_DQ<17>")
	)
	(segment
		(start 318.013588 -286.963358)
		(end 314.511944 -290.465002)
		(width 0.18288)
		(layer "In4.Cu")
		(net "M_C_CPU0_SA_DQ<17>")
	)
	(segment
		(start 283.200094 -296.342816)
		(end 280.243026 -296.342816)
		(width 0.18288)
		(layer "In4.Cu")
		(net "M_C_CPU0_SA_DQ<17>")
	)
	(segment
		(start 312.529474 -291.300662)
		(end 312.529474 -291.17925)
		(width 0.18288)
		(layer "In4.Cu")
		(net "M_C_CPU0_SA_DQ<17>")
	)
	(segment
		(start 300.448726 -296.069258)
		(end 299.7962 -296.339514)
		(width 0.18288)
		(layer "In4.Cu")
		(net "M_C_CPU0_SA_DQ<17>")
	)
	(segment
		(start 298.337224 -296.158158)
		(end 298.177204 -295.998138)
		(width 0.18288)
		(layer "In4.Cu")
		(net "M_C_CPU0_SA_DQ<17>")
	)
	(segment
		(start 312.916062 -291.460682)
		(end 312.689494 -291.460682)
		(width 0.18288)
		(layer "In4.Cu")
		(net "M_C_CPU0_SA_DQ<17>")
	)
	(segment
		(start 337.79587 -269.061184)
		(end 337.792314 -269.059152)
		(width 0.088646)
		(layer "In4.Cu")
		(net "M_C_CPU0_SA_DQ<17>")
	)
	(segment
		(start 298.177204 -295.998138)
		(end 297.803824 -295.998138)
		(width 0.18288)
		(layer "In4.Cu")
		(net "M_C_CPU0_SA_DQ<17>")
	)
	(segment
		(start 339.377274 -269.012924)
		(end 339.297264 -269.059152)
		(width 0.088646)
		(layer "In4.Cu")
		(net "M_C_CPU0_SA_DQ<17>")
	)
	(segment
		(start 302.018192 -294.499792)
		(end 300.448726 -296.069258)
		(width 0.18288)
		(layer "In4.Cu")
		(net "M_C_CPU0_SA_DQ<17>")
	)
	(segment
		(start 283.718 -296.34307)
		(end 283.200348 -296.34307)
		(width 0.18288)
		(layer "In4.Cu")
		(net "M_C_CPU0_SA_DQ<17>")
	)
	(segment
		(start 310.34863 -292.011862)
		(end 309.646828 -292.011862)
		(width 0.18288)
		(layer "In4.Cu")
		(net "M_C_CPU0_SA_DQ<17>")
	)
	(segment
		(start 297.803824 -295.998138)
		(end 297.643804 -296.158158)
		(width 0.18288)
		(layer "In4.Cu")
		(net "M_C_CPU0_SA_DQ<17>")
	)
	(segment
		(start 284.22092 -296.342054)
		(end 284.220666 -296.3418)
		(width 0.18288)
		(layer "In4.Cu")
		(net "M_C_CPU0_SA_DQ<17>")
	)
	(segment
		(start 309.646828 -292.011862)
		(end 308.240938 -293.417752)
		(width 0.18288)
		(layer "In4.Cu")
		(net "M_C_CPU0_SA_DQ<17>")
	)
	(segment
		(start 303.425352 -294.783764)
		(end 303.14138 -294.499792)
		(width 0.18288)
		(layer "In4.Cu")
		(net "M_C_CPU0_SA_DQ<17>")
	)
	(segment
		(start 280.243026 -296.342816)
		(end 279.816814 -295.916604)
		(width 0.18288)
		(layer "In4.Cu")
		(net "M_C_CPU0_SA_DQ<17>")
	)
	(segment
		(start 292.421564 -297.192954)
		(end 291.570664 -296.342054)
		(width 0.18288)
		(layer "In4.Cu")
		(net "M_C_CPU0_SA_DQ<17>")
	)
	(segment
		(start 314.511944 -290.465002)
		(end 313.911742 -290.465002)
		(width 0.18288)
		(layer "In4.Cu")
		(net "M_C_CPU0_SA_DQ<17>")
	)
	(segment
		(start 312.529474 -291.17925)
		(end 312.369454 -291.01923)
		(width 0.18288)
		(layer "In4.Cu")
		(net "M_C_CPU0_SA_DQ<17>")
	)
	(segment
		(start 297.643804 -296.177716)
		(end 297.44162 -296.3799)
		(width 0.18288)
		(layer "In4.Cu")
		(net "M_C_CPU0_SA_DQ<17>")
	)
	(segment
		(start 335.91627 -269.061184)
		(end 335.912714 -269.059152)
		(width 0.088646)
		(layer "In4.Cu")
		(net "M_C_CPU0_SA_DQ<17>")
	)
	(segment
		(start 332.146148 -270.045434)
		(end 331.569822 -270.62176)
		(width 0.088646)
		(layer "In4.Cu")
		(net "M_C_CPU0_SA_DQ<17>")
	)
	(segment
		(start 283.200348 -296.34307)
		(end 283.200094 -296.342816)
		(width 0.18288)
		(layer "In4.Cu")
		(net "M_C_CPU0_SA_DQ<17>")
	)
	(segment
		(start 336.852514 -269.059152)
		(end 336.846672 -269.05585)
		(width 0.088646)
		(layer "In4.Cu")
		(net "M_C_CPU0_SA_DQ<17>")
	)
	(segment
		(start 312.369454 -291.01923)
		(end 311.341262 -291.01923)
		(width 0.18288)
		(layer "In4.Cu")
		(net "M_C_CPU0_SA_DQ<17>")
	)
	(segment
		(start 332.146148 -269.729712)
		(end 332.146148 -270.045434)
		(width 0.088646)
		(layer "In4.Cu")
		(net "M_C_CPU0_SA_DQ<17>")
	)
	(segment
		(start 298.337224 -296.177716)
		(end 298.337224 -296.158158)
		(width 0.18288)
		(layer "In4.Cu")
		(net "M_C_CPU0_SA_DQ<17>")
	)
	(segment
		(start 297.44162 -296.3799)
		(end 296.231818 -296.3799)
		(width 0.18288)
		(layer "In4.Cu")
		(net "M_C_CPU0_SA_DQ<17>")
	)
	(segment
		(start 298.499022 -296.339514)
		(end 298.337224 -296.177716)
		(width 0.18288)
		(layer "In4.Cu")
		(net "M_C_CPU0_SA_DQ<17>")
	)
	(segment
		(start 335.912714 -269.059152)
		(end 335.91246 -269.059152)
		(width 0.088646)
		(layer "In4.Cu")
		(net "M_C_CPU0_SA_DQ<17>")
	)
	(segment
		(start 306.816506 -293.583868)
		(end 305.220878 -294.244522)
		(width 0.18288)
		(layer "In4.Cu")
		(net "M_C_CPU0_SA_DQ<17>")
	)
	(segment
		(start 295.418764 -297.192954)
		(end 292.421564 -297.192954)
		(width 0.18288)
		(layer "In4.Cu")
		(net "M_C_CPU0_SA_DQ<17>")
	)
	(segment
		(start 283.71927 -296.3418)
		(end 283.718 -296.34307)
		(width 0.18288)
		(layer "In4.Cu")
		(net "M_C_CPU0_SA_DQ<17>")
	)
	(segment
		(start 311.341262 -291.01923)
		(end 310.34863 -292.011862)
		(width 0.18288)
		(layer "In4.Cu")
		(net "M_C_CPU0_SA_DQ<17>")
	)
	(segment
		(start 331.258672 -270.62176)
		(end 330.86167 -270.62176)
		(width 0.18288)
		(layer "In4.Cu")
		(net "M_C_CPU0_SA_DQ<17>")
	)
	(segment
		(start 332.47457 -269.40129)
		(end 332.146148 -269.729712)
		(width 0.088646)
		(layer "In4.Cu")
		(net "M_C_CPU0_SA_DQ<17>")
	)
	(segment
		(start 313.911742 -290.465002)
		(end 312.916062 -291.460682)
		(width 0.18288)
		(layer "In4.Cu")
		(net "M_C_CPU0_SA_DQ<17>")
	)
	(segment
		(start 297.643804 -296.158158)
		(end 297.643804 -296.177716)
		(width 0.18288)
		(layer "In4.Cu")
		(net "M_C_CPU0_SA_DQ<17>")
	)
	(segment
		(start 304.681636 -294.783764)
		(end 303.425352 -294.783764)
		(width 0.18288)
		(layer "In4.Cu")
		(net "M_C_CPU0_SA_DQ<17>")
	)
	(segment
		(start 312.689494 -291.460682)
		(end 312.529474 -291.300662)
		(width 0.18288)
		(layer "In4.Cu")
		(net "M_C_CPU0_SA_DQ<17>")
	)
	(segment
		(start 336.857086 -269.061946)
		(end 336.852514 -269.059152)
		(width 0.088646)
		(layer "In4.Cu")
		(net "M_C_CPU0_SA_DQ<17>")
	)
	(segment
		(start 330.86167 -270.62176)
		(end 320.484246 -280.999184)
		(width 0.18288)
		(layer "In4.Cu")
		(net "M_C_CPU0_SA_DQ<17>")
	)
	(segment
		(start 296.231818 -296.3799)
		(end 295.418764 -297.192954)
		(width 0.18288)
		(layer "In4.Cu")
		(net "M_C_CPU0_SA_DQ<17>")
	)
	(segment
		(start 307.840126 -293.583868)
		(end 306.816506 -293.583868)
		(width 0.18288)
		(layer "In4.Cu")
		(net "M_C_CPU0_SA_DQ<17>")
	)
	(arc
		(start 339.297264 -269.059152)
		(mid 339.01809 -269.134917)
		(end 338.737956 -269.062708)
		(width 0.088646)
		(layer "In4.Cu")
		(net "M_C_CPU0_SA_DQ<17>")
	)
	(arc
		(start 334.03286 -269.059152)
		(mid 333.845662 -269.009009)
		(end 333.658464 -269.059152)
		(width 0.088646)
		(layer "In4.Cu")
		(net "M_C_CPU0_SA_DQ<17>")
	)
	(arc
		(start 337.792314 -269.059152)
		(mid 337.605006 -269.009009)
		(end 337.417664 -269.059152)
		(width 0.088646)
		(layer "In4.Cu")
		(net "M_C_CPU0_SA_DQ<17>")
	)
	(arc
		(start 333.658464 -269.059152)
		(mid 333.126858 -269.282634)
		(end 332.556358 -269.366746)
		(width 0.088646)
		(layer "In4.Cu")
		(net "M_C_CPU0_SA_DQ<17>")
	)
	(arc
		(start 337.417664 -269.059152)
		(mid 337.13775 -269.134921)
		(end 336.857086 -269.061946)
		(width 0.088646)
		(layer "In4.Cu")
		(net "M_C_CPU0_SA_DQ<17>")
	)
	(arc
		(start 335.538064 -269.059152)
		(mid 335.255362 -269.134928)
		(end 334.97266 -269.059152)
		(width 0.088646)
		(layer "In4.Cu")
		(net "M_C_CPU0_SA_DQ<17>")
	)
	(arc
		(start 334.97266 -269.059152)
		(mid 334.785462 -269.009009)
		(end 334.598264 -269.059152)
		(width 0.088646)
		(layer "In4.Cu")
		(net "M_C_CPU0_SA_DQ<17>")
	)
	(arc
		(start 334.598264 -269.059152)
		(mid 334.315562 -269.134928)
		(end 334.03286 -269.059152)
		(width 0.088646)
		(layer "In4.Cu")
		(net "M_C_CPU0_SA_DQ<17>")
	)
	(arc
		(start 336.846672 -269.05585)
		(mid 336.661817 -269.0089)
		(end 336.477864 -269.059152)
		(width 0.088646)
		(layer "In4.Cu")
		(net "M_C_CPU0_SA_DQ<17>")
	)
	(arc
		(start 335.91246 -269.059152)
		(mid 335.725262 -269.009009)
		(end 335.538064 -269.059152)
		(width 0.088646)
		(layer "In4.Cu")
		(net "M_C_CPU0_SA_DQ<17>")
	)
	(arc
		(start 339.954616 -268.569694)
		(mid 339.680454 -268.81021)
		(end 339.377274 -269.012924)
		(width 0.088646)
		(layer "In4.Cu")
		(net "M_C_CPU0_SA_DQ<17>")
	)
	(arc
		(start 332.556358 -269.366746)
		(mid 332.512083 -269.376036)
		(end 332.47457 -269.40129)
		(width 0.088646)
		(layer "In4.Cu")
		(net "M_C_CPU0_SA_DQ<17>")
	)
	(arc
		(start 336.477864 -269.059152)
		(mid 336.197353 -269.134798)
		(end 335.91627 -269.061184)
		(width 0.088646)
		(layer "In4.Cu")
		(net "M_C_CPU0_SA_DQ<17>")
	)
	(arc
		(start 338.726272 -269.05585)
		(mid 338.541417 -269.0089)
		(end 338.357464 -269.059152)
		(width 0.088646)
		(layer "In4.Cu")
		(net "M_C_CPU0_SA_DQ<17>")
	)
	(arc
		(start 338.357464 -269.059152)
		(mid 338.076953 -269.134798)
		(end 337.79587 -269.061184)
		(width 0.088646)
		(layer "In4.Cu")
		(net "M_C_CPU0_SA_DQ<17>")
	)
	(segment
		(start 274.40001 -297.191684)
		(end 274.152106 -297.191684)
		(width 0.101854)
		(layer "F.Cu")
		(net "M_C_CPU0_SA_DQ<16>")
	)
	(segment
		(start 273.19986 -297.855386)
		(end 272.741136 -297.855386)
		(width 0.20066)
		(layer "F.Cu")
		(net "M_C_CPU0_SA_DQ<16>")
	)
	(segment
		(start 276.917912 -297.191684)
		(end 276.469094 -297.191684)
		(width 0.20066)
		(layer "F.Cu")
		(net "M_C_CPU0_SA_DQ<16>")
	)
	(segment
		(start 340.424516 -268.84757)
		(end 340.424262 -268.847824)
		(width 0.20066)
		(layer "F.Cu")
		(net "M_C_CPU0_SA_DQ<16>")
	)
	(segment
		(start 273.58213 -297.183556)
		(end 273.37258 -297.393106)
		(width 0.20066)
		(layer "F.Cu")
		(net "M_C_CPU0_SA_DQ<16>")
	)
	(segment
		(start 272.502376 -297.616626)
		(end 271.168114 -297.616626)
		(width 0.20066)
		(layer "F.Cu")
		(net "M_C_CPU0_SA_DQ<16>")
	)
	(segment
		(start 278.711914 -297.616626)
		(end 277.342854 -297.616626)
		(width 0.20066)
		(layer "F.Cu")
		(net "M_C_CPU0_SA_DQ<16>")
	)
	(segment
		(start 279.816814 -297.616626)
		(end 278.711914 -297.616626)
		(width 0.20066)
		(layer "F.Cu")
		(net "M_C_CPU0_SA_DQ<16>")
	)
	(segment
		(start 274.152106 -297.191684)
		(end 274.143978 -297.183556)
		(width 0.101854)
		(layer "F.Cu")
		(net "M_C_CPU0_SA_DQ<16>")
	)
	(segment
		(start 340.424262 -268.847824)
		(end 340.424262 -269.38351)
		(width 0.20066)
		(layer "F.Cu")
		(net "M_C_CPU0_SA_DQ<16>")
	)
	(segment
		(start 276.469094 -297.191684)
		(end 274.40001 -297.191684)
		(width 0.1016)
		(layer "F.Cu")
		(net "M_C_CPU0_SA_DQ<16>")
	)
	(segment
		(start 273.37258 -297.682666)
		(end 273.19986 -297.855386)
		(width 0.20066)
		(layer "F.Cu")
		(net "M_C_CPU0_SA_DQ<16>")
	)
	(segment
		(start 277.342854 -297.616626)
		(end 276.917912 -297.191684)
		(width 0.20066)
		(layer "F.Cu")
		(net "M_C_CPU0_SA_DQ<16>")
	)
	(segment
		(start 274.143978 -297.183556)
		(end 273.58213 -297.183556)
		(width 0.20066)
		(layer "F.Cu")
		(net "M_C_CPU0_SA_DQ<16>")
	)
	(segment
		(start 273.37258 -297.393106)
		(end 273.37258 -297.682666)
		(width 0.20066)
		(layer "F.Cu")
		(net "M_C_CPU0_SA_DQ<16>")
	)
	(segment
		(start 272.741136 -297.855386)
		(end 272.502376 -297.616626)
		(width 0.20066)
		(layer "F.Cu")
		(net "M_C_CPU0_SA_DQ<16>")
	)
	(segment
		(start 333.798418 -269.946882)
		(end 333.268828 -269.946882)
		(width 0.088646)
		(layer "In4.Cu")
		(net "M_C_CPU0_SA_DQ<16>")
	)
	(segment
		(start 307.66639 -294.60063)
		(end 307.43525 -294.696388)
		(width 0.18288)
		(layer "In4.Cu")
		(net "M_C_CPU0_SA_DQ<16>")
	)
	(segment
		(start 307.125878 -295.00576)
		(end 306.335176 -295.33342)
		(width 0.18288)
		(layer "In4.Cu")
		(net "M_C_CPU0_SA_DQ<16>")
	)
	(segment
		(start 295.463722 -298.889674)
		(end 292.24986 -298.889674)
		(width 0.18288)
		(layer "In4.Cu")
		(net "M_C_CPU0_SA_DQ<16>")
	)
	(segment
		(start 306.335176 -295.33342)
		(end 305.743102 -295.33342)
		(width 0.18288)
		(layer "In4.Cu")
		(net "M_C_CPU0_SA_DQ<16>")
	)
	(segment
		(start 318.832992 -287.69183)
		(end 313.863482 -292.66134)
		(width 0.18288)
		(layer "In4.Cu")
		(net "M_C_CPU0_SA_DQ<16>")
	)
	(segment
		(start 333.268828 -269.946882)
		(end 331.59827 -271.61744)
		(width 0.088646)
		(layer "In4.Cu")
		(net "M_C_CPU0_SA_DQ<16>")
	)
	(segment
		(start 309.275734 -293.838122)
		(end 308.737508 -294.376348)
		(width 0.18288)
		(layer "In4.Cu")
		(net "M_C_CPU0_SA_DQ<16>")
	)
	(segment
		(start 331.424534 -271.61744)
		(end 331.275436 -271.61744)
		(width 0.18288)
		(layer "In4.Cu")
		(net "M_C_CPU0_SA_DQ<16>")
	)
	(segment
		(start 340.62035 -269.064232)
		(end 340.61146 -269.059152)
		(width 0.088646)
		(layer "In4.Cu")
		(net "M_C_CPU0_SA_DQ<16>")
	)
	(segment
		(start 339.767164 -269.873222)
		(end 339.75675 -269.879318)
		(width 0.088646)
		(layer "In4.Cu")
		(net "M_C_CPU0_SA_DQ<16>")
	)
	(segment
		(start 340.049866 -269.374874)
		(end 340.049866 -269.397734)
		(width 0.088646)
		(layer "In4.Cu")
		(net "M_C_CPU0_SA_DQ<16>")
	)
	(segment
		(start 308.737508 -294.376348)
		(end 308.196996 -294.60063)
		(width 0.18288)
		(layer "In4.Cu")
		(net "M_C_CPU0_SA_DQ<16>")
	)
	(segment
		(start 304.73269 -296.343832)
		(end 302.076866 -296.343832)
		(width 0.18288)
		(layer "In4.Cu")
		(net "M_C_CPU0_SA_DQ<16>")
	)
	(segment
		(start 292.24986 -298.889674)
		(end 291.402008 -298.041822)
		(width 0.18288)
		(layer "In4.Cu")
		(net "M_C_CPU0_SA_DQ<16>")
	)
	(segment
		(start 312.118502 -292.66134)
		(end 309.275734 -293.838122)
		(width 0.18288)
		(layer "In4.Cu")
		(net "M_C_CPU0_SA_DQ<16>")
	)
	(segment
		(start 307.43525 -294.696388)
		(end 307.125878 -295.00576)
		(width 0.18288)
		(layer "In4.Cu")
		(net "M_C_CPU0_SA_DQ<16>")
	)
	(segment
		(start 313.863482 -292.66134)
		(end 312.118502 -292.66134)
		(width 0.18288)
		(layer "In4.Cu")
		(net "M_C_CPU0_SA_DQ<16>")
	)
	(segment
		(start 338.272374 -269.879318)
		(end 338.26196 -269.873222)
		(width 0.088646)
		(layer "In4.Cu")
		(net "M_C_CPU0_SA_DQ<16>")
	)
	(segment
		(start 302.076866 -296.343832)
		(end 300.378622 -298.042076)
		(width 0.18288)
		(layer "In4.Cu")
		(net "M_C_CPU0_SA_DQ<16>")
	)
	(segment
		(start 340.42985 -269.389098)
		(end 340.731348 -269.389098)
		(width 0.088646)
		(layer "In4.Cu")
		(net "M_C_CPU0_SA_DQ<16>")
	)
	(segment
		(start 291.402008 -298.041822)
		(end 280.24201 -298.041822)
		(width 0.18288)
		(layer "In4.Cu")
		(net "M_C_CPU0_SA_DQ<16>")
	)
	(segment
		(start 300.378622 -298.042076)
		(end 298.49826 -298.042076)
		(width 0.18288)
		(layer "In4.Cu")
		(net "M_C_CPU0_SA_DQ<16>")
	)
	(segment
		(start 280.24201 -298.041822)
		(end 279.816814 -297.616626)
		(width 0.18288)
		(layer "In4.Cu")
		(net "M_C_CPU0_SA_DQ<16>")
	)
	(segment
		(start 331.275436 -271.61744)
		(end 321.401694 -281.491182)
		(width 0.18288)
		(layer "In4.Cu")
		(net "M_C_CPU0_SA_DQ<16>")
	)
	(segment
		(start 297.995086 -298.54525)
		(end 295.808146 -298.54525)
		(width 0.18288)
		(layer "In4.Cu")
		(net "M_C_CPU0_SA_DQ<16>")
	)
	(segment
		(start 305.743102 -295.33342)
		(end 304.73269 -296.343832)
		(width 0.18288)
		(layer "In4.Cu")
		(net "M_C_CPU0_SA_DQ<16>")
	)
	(segment
		(start 340.731348 -269.389098)
		(end 340.79434 -269.326106)
		(width 0.088646)
		(layer "In4.Cu")
		(net "M_C_CPU0_SA_DQ<16>")
	)
	(segment
		(start 331.59827 -271.61744)
		(end 331.424534 -271.61744)
		(width 0.088646)
		(layer "In4.Cu")
		(net "M_C_CPU0_SA_DQ<16>")
	)
	(segment
		(start 298.49826 -298.042076)
		(end 297.995086 -298.54525)
		(width 0.18288)
		(layer "In4.Cu")
		(net "M_C_CPU0_SA_DQ<16>")
	)
	(segment
		(start 340.424262 -269.38351)
		(end 340.42985 -269.389098)
		(width 0.088646)
		(layer "In4.Cu")
		(net "M_C_CPU0_SA_DQ<16>")
	)
	(segment
		(start 295.808146 -298.54525)
		(end 295.463722 -298.889674)
		(width 0.18288)
		(layer "In4.Cu")
		(net "M_C_CPU0_SA_DQ<16>")
	)
	(segment
		(start 321.401694 -281.491182)
		(end 318.832992 -287.69183)
		(width 0.18288)
		(layer "In4.Cu")
		(net "M_C_CPU0_SA_DQ<16>")
	)
	(segment
		(start 308.196996 -294.60063)
		(end 307.66639 -294.60063)
		(width 0.18288)
		(layer "In4.Cu")
		(net "M_C_CPU0_SA_DQ<16>")
	)
	(arc
		(start 335.44256 -269.873222)
		(mid 335.255362 -269.823079)
		(end 335.068164 -269.873222)
		(width 0.088646)
		(layer "In4.Cu")
		(net "M_C_CPU0_SA_DQ<16>")
	)
	(arc
		(start 336.38236 -269.873222)
		(mid 336.195162 -269.823079)
		(end 336.007964 -269.873222)
		(width 0.088646)
		(layer "In4.Cu")
		(net "M_C_CPU0_SA_DQ<16>")
	)
	(arc
		(start 338.26196 -269.873222)
		(mid 338.074762 -269.823079)
		(end 337.887564 -269.873222)
		(width 0.088646)
		(layer "In4.Cu")
		(net "M_C_CPU0_SA_DQ<16>")
	)
	(arc
		(start 336.947764 -269.873222)
		(mid 336.665062 -269.948964)
		(end 336.38236 -269.873222)
		(width 0.088646)
		(layer "In4.Cu")
		(net "M_C_CPU0_SA_DQ<16>")
	)
	(arc
		(start 339.202014 -269.873222)
		(mid 339.014816 -269.823079)
		(end 338.827618 -269.873222)
		(width 0.088646)
		(layer "In4.Cu")
		(net "M_C_CPU0_SA_DQ<16>")
	)
	(arc
		(start 340.79434 -269.326106)
		(mid 340.736184 -269.175993)
		(end 340.62035 -269.064232)
		(width 0.088646)
		(layer "In4.Cu")
		(net "M_C_CPU0_SA_DQ<16>")
	)
	(arc
		(start 337.887564 -269.873222)
		(mid 337.604862 -269.948964)
		(end 337.32216 -269.873222)
		(width 0.088646)
		(layer "In4.Cu")
		(net "M_C_CPU0_SA_DQ<16>")
	)
	(arc
		(start 334.50276 -269.873222)
		(mid 334.315562 -269.823079)
		(end 334.128364 -269.873222)
		(width 0.088646)
		(layer "In4.Cu")
		(net "M_C_CPU0_SA_DQ<16>")
	)
	(arc
		(start 340.049866 -269.397734)
		(mid 339.970647 -269.672419)
		(end 339.767164 -269.873222)
		(width 0.088646)
		(layer "In4.Cu")
		(net "M_C_CPU0_SA_DQ<16>")
	)
	(arc
		(start 336.007964 -269.873222)
		(mid 335.725262 -269.948964)
		(end 335.44256 -269.873222)
		(width 0.088646)
		(layer "In4.Cu")
		(net "M_C_CPU0_SA_DQ<16>")
	)
	(arc
		(start 335.068164 -269.873222)
		(mid 334.785462 -269.948964)
		(end 334.50276 -269.873222)
		(width 0.088646)
		(layer "In4.Cu")
		(net "M_C_CPU0_SA_DQ<16>")
	)
	(arc
		(start 339.75675 -269.879318)
		(mid 339.478572 -269.94901)
		(end 339.202014 -269.873222)
		(width 0.088646)
		(layer "In4.Cu")
		(net "M_C_CPU0_SA_DQ<16>")
	)
	(arc
		(start 340.61146 -269.059152)
		(mid 340.424262 -269.009009)
		(end 340.237064 -269.059152)
		(width 0.088646)
		(layer "In4.Cu")
		(net "M_C_CPU0_SA_DQ<16>")
	)
	(arc
		(start 334.128364 -269.873222)
		(mid 333.969024 -269.93527)
		(end 333.798418 -269.946882)
		(width 0.088646)
		(layer "In4.Cu")
		(net "M_C_CPU0_SA_DQ<16>")
	)
	(arc
		(start 338.827618 -269.873222)
		(mid 338.550805 -269.949058)
		(end 338.272374 -269.879318)
		(width 0.088646)
		(layer "In4.Cu")
		(net "M_C_CPU0_SA_DQ<16>")
	)
	(arc
		(start 337.32216 -269.873222)
		(mid 337.134962 -269.823079)
		(end 336.947764 -269.873222)
		(width 0.088646)
		(layer "In4.Cu")
		(net "M_C_CPU0_SA_DQ<16>")
	)
	(arc
		(start 340.237064 -269.059152)
		(mid 340.102131 -269.192506)
		(end 340.049866 -269.374874)
		(width 0.088646)
		(layer "In4.Cu")
		(net "M_C_CPU0_SA_DQ<16>")
	)
	(segment
		(start 281.788362 -298.674282)
		(end 281.34183 -298.674282)
		(width 0.20066)
		(layer "F.Cu")
		(net "M_C_CPU0_SA_DQ<15>")
	)
	(segment
		(start 277.091394 -298.763436)
		(end 277.091394 -298.592748)
		(width 0.20066)
		(layer "F.Cu")
		(net "M_C_CPU0_SA_DQ<15>")
	)
	(segment
		(start 277.58771 -298.90593)
		(end 277.233888 -298.90593)
		(width 0.20066)
		(layer "F.Cu")
		(net "M_C_CPU0_SA_DQ<15>")
	)
	(segment
		(start 277.233888 -298.90593)
		(end 277.091394 -298.763436)
		(width 0.20066)
		(layer "F.Cu")
		(net "M_C_CPU0_SA_DQ<15>")
	)
	(segment
		(start 344.653362 -268.033754)
		(end 344.653616 -268.034008)
		(width 0.20066)
		(layer "F.Cu")
		(net "M_C_CPU0_SA_DQ<15>")
	)
	(segment
		(start 277.601934 -298.891706)
		(end 277.58771 -298.90593)
		(width 0.101854)
		(layer "F.Cu")
		(net "M_C_CPU0_SA_DQ<15>")
	)
	(segment
		(start 277.839932 -298.891706)
		(end 277.601934 -298.891706)
		(width 0.101854)
		(layer "F.Cu")
		(net "M_C_CPU0_SA_DQ<15>")
	)
	(segment
		(start 283.916882 -298.466764)
		(end 282.811982 -298.466764)
		(width 0.20066)
		(layer "F.Cu")
		(net "M_C_CPU0_SA_DQ<15>")
	)
	(segment
		(start 281.129994 -298.462446)
		(end 280.73477 -298.462446)
		(width 0.20066)
		(layer "F.Cu")
		(net "M_C_CPU0_SA_DQ<15>")
	)
	(segment
		(start 277.091394 -298.592748)
		(end 276.96541 -298.466764)
		(width 0.20066)
		(layer "F.Cu")
		(net "M_C_CPU0_SA_DQ<15>")
	)
	(segment
		(start 281.99588 -298.466764)
		(end 281.788362 -298.674282)
		(width 0.20066)
		(layer "F.Cu")
		(net "M_C_CPU0_SA_DQ<15>")
	)
	(segment
		(start 344.653616 -268.034008)
		(end 344.653616 -268.569694)
		(width 0.20066)
		(layer "F.Cu")
		(net "M_C_CPU0_SA_DQ<15>")
	)
	(segment
		(start 280.606246 -298.59097)
		(end 280.606246 -298.742608)
		(width 0.20066)
		(layer "F.Cu")
		(net "M_C_CPU0_SA_DQ<15>")
	)
	(segment
		(start 276.96541 -298.466764)
		(end 275.268182 -298.466764)
		(width 0.20066)
		(layer "F.Cu")
		(net "M_C_CPU0_SA_DQ<15>")
	)
	(segment
		(start 280.457148 -298.891706)
		(end 279.912826 -298.891706)
		(width 0.20066)
		(layer "F.Cu")
		(net "M_C_CPU0_SA_DQ<15>")
	)
	(segment
		(start 280.73477 -298.462446)
		(end 280.606246 -298.59097)
		(width 0.20066)
		(layer "F.Cu")
		(net "M_C_CPU0_SA_DQ<15>")
	)
	(segment
		(start 280.606246 -298.742608)
		(end 280.457148 -298.891706)
		(width 0.20066)
		(layer "F.Cu")
		(net "M_C_CPU0_SA_DQ<15>")
	)
	(segment
		(start 279.912826 -298.891706)
		(end 277.839932 -298.891706)
		(width 0.1016)
		(layer "F.Cu")
		(net "M_C_CPU0_SA_DQ<15>")
	)
	(segment
		(start 282.811982 -298.466764)
		(end 281.99588 -298.466764)
		(width 0.20066)
		(layer "F.Cu")
		(net "M_C_CPU0_SA_DQ<15>")
	)
	(segment
		(start 281.34183 -298.674282)
		(end 281.129994 -298.462446)
		(width 0.20066)
		(layer "F.Cu")
		(net "M_C_CPU0_SA_DQ<15>")
	)
	(segment
		(start 290.964874 -289.308286)
		(end 290.57854 -288.921952)
		(width 0.18288)
		(layer "In6.Cu")
		(net "M_C_CPU0_SA_DQ<15>")
	)
	(segment
		(start 290.01974 -290.47948)
		(end 288.759392 -290.47948)
		(width 0.18288)
		(layer "In6.Cu")
		(net "M_C_CPU0_SA_DQ<15>")
	)
	(segment
		(start 311.442354 -281.873198)
		(end 310.900318 -282.415234)
		(width 0.18288)
		(layer "In6.Cu")
		(net "M_C_CPU0_SA_DQ<15>")
	)
	(segment
		(start 304.39868 -285.468822)
		(end 303.368964 -285.468822)
		(width 0.18288)
		(layer "In6.Cu")
		(net "M_C_CPU0_SA_DQ<15>")
	)
	(segment
		(start 333.750412 -268.559788)
		(end 333.750412 -268.569694)
		(width 0.088646)
		(layer "In6.Cu")
		(net "M_C_CPU0_SA_DQ<15>")
	)
	(segment
		(start 291.807392 -288.691828)
		(end 291.190934 -289.308286)
		(width 0.18288)
		(layer "In6.Cu")
		(net "M_C_CPU0_SA_DQ<15>")
	)
	(segment
		(start 297.836336 -287.841436)
		(end 296.985944 -288.691828)
		(width 0.18288)
		(layer "In6.Cu")
		(net "M_C_CPU0_SA_DQ<15>")
	)
	(segment
		(start 321.753484 -274.5105)
		(end 315.147198 -281.116786)
		(width 0.18288)
		(layer "In6.Cu")
		(net "M_C_CPU0_SA_DQ<15>")
	)
	(segment
		(start 290.088066 -289.186366)
		(end 290.088066 -289.412426)
		(width 0.18288)
		(layer "In6.Cu")
		(net "M_C_CPU0_SA_DQ<15>")
	)
	(segment
		(start 344.340942 -268.569694)
		(end 344.275156 -268.503908)
		(width 0.088646)
		(layer "In6.Cu")
		(net "M_C_CPU0_SA_DQ<15>")
	)
	(segment
		(start 331.283056 -270.936212)
		(end 330.384658 -270.936212)
		(width 0.18288)
		(layer "In6.Cu")
		(net "M_C_CPU0_SA_DQ<15>")
	)
	(segment
		(start 331.53858 -270.936212)
		(end 331.283056 -270.936212)
		(width 0.088646)
		(layer "In6.Cu")
		(net "M_C_CPU0_SA_DQ<15>")
	)
	(segment
		(start 340.237064 -268.080236)
		(end 340.222332 -268.0716)
		(width 0.088646)
		(layer "In6.Cu")
		(net "M_C_CPU0_SA_DQ<15>")
	)
	(segment
		(start 291.190934 -289.308286)
		(end 290.964874 -289.308286)
		(width 0.18288)
		(layer "In6.Cu")
		(net "M_C_CPU0_SA_DQ<15>")
	)
	(segment
		(start 337.802474 -268.07414)
		(end 337.79206 -268.080236)
		(width 0.088646)
		(layer "In6.Cu")
		(net "M_C_CPU0_SA_DQ<15>")
	)
	(segment
		(start 310.154066 -283.621226)
		(end 306.246276 -283.621226)
		(width 0.18288)
		(layer "In6.Cu")
		(net "M_C_CPU0_SA_DQ<15>")
	)
	(segment
		(start 290.088066 -289.412426)
		(end 290.4744 -289.79876)
		(width 0.18288)
		(layer "In6.Cu")
		(net "M_C_CPU0_SA_DQ<15>")
	)
	(segment
		(start 290.35248 -288.921952)
		(end 290.088066 -289.186366)
		(width 0.18288)
		(layer "In6.Cu")
		(net "M_C_CPU0_SA_DQ<15>")
	)
	(segment
		(start 296.985944 -288.691828)
		(end 293.854378 -288.691828)
		(width 0.18288)
		(layer "In6.Cu")
		(net "M_C_CPU0_SA_DQ<15>")
	)
	(segment
		(start 303.368964 -285.468822)
		(end 302.553624 -286.284162)
		(width 0.18288)
		(layer "In6.Cu")
		(net "M_C_CPU0_SA_DQ<15>")
	)
	(segment
		(start 344.653616 -268.569694)
		(end 344.340942 -268.569694)
		(width 0.088646)
		(layer "In6.Cu")
		(net "M_C_CPU0_SA_DQ<15>")
	)
	(segment
		(start 293.694358 -288.531808)
		(end 293.694358 -287.993328)
		(width 0.18288)
		(layer "In6.Cu")
		(net "M_C_CPU0_SA_DQ<15>")
	)
	(segment
		(start 300.512988 -287.841436)
		(end 297.836336 -287.841436)
		(width 0.18288)
		(layer "In6.Cu")
		(net "M_C_CPU0_SA_DQ<15>")
	)
	(segment
		(start 293.694358 -287.993328)
		(end 293.523416 -287.822386)
		(width 0.18288)
		(layer "In6.Cu")
		(net "M_C_CPU0_SA_DQ<15>")
	)
	(segment
		(start 344.00236 -268.083792)
		(end 343.996264 -268.080236)
		(width 0.088646)
		(layer "In6.Cu")
		(net "M_C_CPU0_SA_DQ<15>")
	)
	(segment
		(start 290.4744 -290.02482)
		(end 290.01974 -290.47948)
		(width 0.18288)
		(layer "In6.Cu")
		(net "M_C_CPU0_SA_DQ<15>")
	)
	(segment
		(start 293.523416 -287.822386)
		(end 293.160958 -287.822386)
		(width 0.18288)
		(layer "In6.Cu")
		(net "M_C_CPU0_SA_DQ<15>")
	)
	(segment
		(start 342.116664 -268.080236)
		(end 342.101932 -268.0716)
		(width 0.088646)
		(layer "In6.Cu")
		(net "M_C_CPU0_SA_DQ<15>")
	)
	(segment
		(start 310.900318 -282.415234)
		(end 310.900318 -282.874974)
		(width 0.18288)
		(layer "In6.Cu")
		(net "M_C_CPU0_SA_DQ<15>")
	)
	(segment
		(start 332.122018 -269.71371)
		(end 332.122018 -270.352774)
		(width 0.088646)
		(layer "In6.Cu")
		(net "M_C_CPU0_SA_DQ<15>")
	)
	(segment
		(start 290.4744 -289.79876)
		(end 290.4744 -290.02482)
		(width 0.18288)
		(layer "In6.Cu")
		(net "M_C_CPU0_SA_DQ<15>")
	)
	(segment
		(start 286.976566 -292.262306)
		(end 286.717994 -292.262306)
		(width 0.18288)
		(layer "In6.Cu")
		(net "M_C_CPU0_SA_DQ<15>")
	)
	(segment
		(start 288.759392 -290.47948)
		(end 286.976566 -292.262306)
		(width 0.18288)
		(layer "In6.Cu")
		(net "M_C_CPU0_SA_DQ<15>")
	)
	(segment
		(start 341.176864 -268.080236)
		(end 341.162132 -268.0716)
		(width 0.088646)
		(layer "In6.Cu")
		(net "M_C_CPU0_SA_DQ<15>")
	)
	(segment
		(start 293.160958 -287.822386)
		(end 293.000938 -287.982406)
		(width 0.18288)
		(layer "In6.Cu")
		(net "M_C_CPU0_SA_DQ<15>")
	)
	(segment
		(start 286.717994 -292.262306)
		(end 285.717996 -291.262308)
		(width 0.18288)
		(layer "In6.Cu")
		(net "M_C_CPU0_SA_DQ<15>")
	)
	(segment
		(start 293.000938 -287.982406)
		(end 293.000938 -288.531808)
		(width 0.18288)
		(layer "In6.Cu")
		(net "M_C_CPU0_SA_DQ<15>")
	)
	(segment
		(start 314.016644 -281.116786)
		(end 313.260232 -281.873198)
		(width 0.18288)
		(layer "In6.Cu")
		(net "M_C_CPU0_SA_DQ<15>")
	)
	(segment
		(start 302.553624 -286.284162)
		(end 302.070262 -286.284162)
		(width 0.18288)
		(layer "In6.Cu")
		(net "M_C_CPU0_SA_DQ<15>")
	)
	(segment
		(start 306.246276 -283.621226)
		(end 304.39868 -285.468822)
		(width 0.18288)
		(layer "In6.Cu")
		(net "M_C_CPU0_SA_DQ<15>")
	)
	(segment
		(start 292.840918 -288.691828)
		(end 291.807392 -288.691828)
		(width 0.18288)
		(layer "In6.Cu")
		(net "M_C_CPU0_SA_DQ<15>")
	)
	(segment
		(start 286.229298 -293.009574)
		(end 284.555946 -294.682926)
		(width 0.18288)
		(layer "In6.Cu")
		(net "M_C_CPU0_SA_DQ<15>")
	)
	(segment
		(start 293.854378 -288.691828)
		(end 293.694358 -288.531808)
		(width 0.18288)
		(layer "In6.Cu")
		(net "M_C_CPU0_SA_DQ<15>")
	)
	(segment
		(start 290.57854 -288.921952)
		(end 290.35248 -288.921952)
		(width 0.18288)
		(layer "In6.Cu")
		(net "M_C_CPU0_SA_DQ<15>")
	)
	(segment
		(start 343.996264 -268.080236)
		(end 343.981532 -268.0716)
		(width 0.088646)
		(layer "In6.Cu")
		(net "M_C_CPU0_SA_DQ<15>")
	)
	(segment
		(start 330.384658 -270.936212)
		(end 321.753484 -274.5105)
		(width 0.18288)
		(layer "In6.Cu")
		(net "M_C_CPU0_SA_DQ<15>")
	)
	(segment
		(start 315.147198 -281.116786)
		(end 314.016644 -281.116786)
		(width 0.18288)
		(layer "In6.Cu")
		(net "M_C_CPU0_SA_DQ<15>")
	)
	(segment
		(start 339.297264 -268.080236)
		(end 339.28685 -268.07414)
		(width 0.088646)
		(layer "In6.Cu")
		(net "M_C_CPU0_SA_DQ<15>")
	)
	(segment
		(start 313.260232 -281.873198)
		(end 311.442354 -281.873198)
		(width 0.18288)
		(layer "In6.Cu")
		(net "M_C_CPU0_SA_DQ<15>")
	)
	(segment
		(start 310.900318 -282.874974)
		(end 310.154066 -283.621226)
		(width 0.18288)
		(layer "In6.Cu")
		(net "M_C_CPU0_SA_DQ<15>")
	)
	(segment
		(start 284.555946 -294.682926)
		(end 284.555946 -297.8277)
		(width 0.18288)
		(layer "In6.Cu")
		(net "M_C_CPU0_SA_DQ<15>")
	)
	(segment
		(start 285.2293 -291.751004)
		(end 286.229298 -292.751002)
		(width 0.18288)
		(layer "In6.Cu")
		(net "M_C_CPU0_SA_DQ<15>")
	)
	(segment
		(start 285.2293 -291.492432)
		(end 285.2293 -291.751004)
		(width 0.18288)
		(layer "In6.Cu")
		(net "M_C_CPU0_SA_DQ<15>")
	)
	(segment
		(start 293.000938 -288.531808)
		(end 292.840918 -288.691828)
		(width 0.18288)
		(layer "In6.Cu")
		(net "M_C_CPU0_SA_DQ<15>")
	)
	(segment
		(start 333.0575 -269.37208)
		(end 332.463648 -269.37208)
		(width 0.088646)
		(layer "In6.Cu")
		(net "M_C_CPU0_SA_DQ<15>")
	)
	(segment
		(start 285.459424 -291.262308)
		(end 285.2293 -291.492432)
		(width 0.18288)
		(layer "In6.Cu")
		(net "M_C_CPU0_SA_DQ<15>")
	)
	(segment
		(start 285.717996 -291.262308)
		(end 285.459424 -291.262308)
		(width 0.18288)
		(layer "In6.Cu")
		(net "M_C_CPU0_SA_DQ<15>")
	)
	(segment
		(start 333.445866 -268.983714)
		(end 333.0575 -269.37208)
		(width 0.088646)
		(layer "In6.Cu")
		(net "M_C_CPU0_SA_DQ<15>")
	)
	(segment
		(start 302.070262 -286.284162)
		(end 300.512988 -287.841436)
		(width 0.18288)
		(layer "In6.Cu")
		(net "M_C_CPU0_SA_DQ<15>")
	)
	(segment
		(start 332.463648 -269.37208)
		(end 332.122018 -269.71371)
		(width 0.088646)
		(layer "In6.Cu")
		(net "M_C_CPU0_SA_DQ<15>")
	)
	(segment
		(start 286.229298 -292.751002)
		(end 286.229298 -293.009574)
		(width 0.18288)
		(layer "In6.Cu")
		(net "M_C_CPU0_SA_DQ<15>")
	)
	(segment
		(start 284.555946 -297.8277)
		(end 283.916882 -298.466764)
		(width 0.18288)
		(layer "In6.Cu")
		(net "M_C_CPU0_SA_DQ<15>")
	)
	(segment
		(start 332.122018 -270.352774)
		(end 331.53858 -270.936212)
		(width 0.088646)
		(layer "In6.Cu")
		(net "M_C_CPU0_SA_DQ<15>")
	)
	(arc
		(start 344.275156 -268.503908)
		(mid 344.187868 -268.261952)
		(end 344.00236 -268.083792)
		(width 0.088646)
		(layer "In6.Cu")
		(net "M_C_CPU0_SA_DQ<15>")
	)
	(arc
		(start 334.03286 -268.080236)
		(mid 333.828525 -268.282841)
		(end 333.750412 -268.559788)
		(width 0.088646)
		(layer "In6.Cu")
		(net "M_C_CPU0_SA_DQ<15>")
	)
	(arc
		(start 339.67166 -268.080236)
		(mid 339.484462 -268.130379)
		(end 339.297264 -268.080236)
		(width 0.088646)
		(layer "In6.Cu")
		(net "M_C_CPU0_SA_DQ<15>")
	)
	(arc
		(start 341.55126 -268.080236)
		(mid 341.364062 -268.130379)
		(end 341.176864 -268.080236)
		(width 0.088646)
		(layer "In6.Cu")
		(net "M_C_CPU0_SA_DQ<15>")
	)
	(arc
		(start 334.598264 -268.080236)
		(mid 334.315562 -268.00446)
		(end 334.03286 -268.080236)
		(width 0.088646)
		(layer "In6.Cu")
		(net "M_C_CPU0_SA_DQ<15>")
	)
	(arc
		(start 343.43086 -268.080236)
		(mid 343.243662 -268.130379)
		(end 343.056464 -268.080236)
		(width 0.088646)
		(layer "In6.Cu")
		(net "M_C_CPU0_SA_DQ<15>")
	)
	(arc
		(start 333.57185 -268.888972)
		(mid 333.505546 -268.931938)
		(end 333.445866 -268.983714)
		(width 0.088646)
		(layer "In6.Cu")
		(net "M_C_CPU0_SA_DQ<15>")
	)
	(arc
		(start 340.61146 -268.080236)
		(mid 340.424262 -268.130379)
		(end 340.237064 -268.080236)
		(width 0.088646)
		(layer "In6.Cu")
		(net "M_C_CPU0_SA_DQ<15>")
	)
	(arc
		(start 334.97266 -268.080236)
		(mid 334.785462 -268.130379)
		(end 334.598264 -268.080236)
		(width 0.088646)
		(layer "In6.Cu")
		(net "M_C_CPU0_SA_DQ<15>")
	)
	(arc
		(start 338.357718 -268.080236)
		(mid 338.080905 -268.004366)
		(end 337.802474 -268.07414)
		(width 0.088646)
		(layer "In6.Cu")
		(net "M_C_CPU0_SA_DQ<15>")
	)
	(arc
		(start 335.538064 -268.080236)
		(mid 335.255362 -268.00446)
		(end 334.97266 -268.080236)
		(width 0.088646)
		(layer "In6.Cu")
		(net "M_C_CPU0_SA_DQ<15>")
	)
	(arc
		(start 336.85226 -268.080236)
		(mid 336.665062 -268.130379)
		(end 336.477864 -268.080236)
		(width 0.088646)
		(layer "In6.Cu")
		(net "M_C_CPU0_SA_DQ<15>")
	)
	(arc
		(start 343.981532 -268.0716)
		(mid 343.705057 -268.00428)
		(end 343.43086 -268.080236)
		(width 0.088646)
		(layer "In6.Cu")
		(net "M_C_CPU0_SA_DQ<15>")
	)
	(arc
		(start 340.222332 -268.0716)
		(mid 339.945857 -268.00428)
		(end 339.67166 -268.080236)
		(width 0.088646)
		(layer "In6.Cu")
		(net "M_C_CPU0_SA_DQ<15>")
	)
	(arc
		(start 337.417664 -268.080236)
		(mid 337.134962 -268.00446)
		(end 336.85226 -268.080236)
		(width 0.088646)
		(layer "In6.Cu")
		(net "M_C_CPU0_SA_DQ<15>")
	)
	(arc
		(start 341.162132 -268.0716)
		(mid 340.885657 -268.00428)
		(end 340.61146 -268.080236)
		(width 0.088646)
		(layer "In6.Cu")
		(net "M_C_CPU0_SA_DQ<15>")
	)
	(arc
		(start 337.79206 -268.080236)
		(mid 337.604862 -268.130379)
		(end 337.417664 -268.080236)
		(width 0.088646)
		(layer "In6.Cu")
		(net "M_C_CPU0_SA_DQ<15>")
	)
	(arc
		(start 338.732114 -268.080236)
		(mid 338.544916 -268.130379)
		(end 338.357718 -268.080236)
		(width 0.088646)
		(layer "In6.Cu")
		(net "M_C_CPU0_SA_DQ<15>")
	)
	(arc
		(start 335.91246 -268.080236)
		(mid 335.725262 -268.130379)
		(end 335.538064 -268.080236)
		(width 0.088646)
		(layer "In6.Cu")
		(net "M_C_CPU0_SA_DQ<15>")
	)
	(arc
		(start 333.750412 -268.569694)
		(mid 333.702733 -268.752594)
		(end 333.57185 -268.888972)
		(width 0.088646)
		(layer "In6.Cu")
		(net "M_C_CPU0_SA_DQ<15>")
	)
	(arc
		(start 343.056464 -268.080236)
		(mid 342.773762 -268.00446)
		(end 342.49106 -268.080236)
		(width 0.088646)
		(layer "In6.Cu")
		(net "M_C_CPU0_SA_DQ<15>")
	)
	(arc
		(start 342.101932 -268.0716)
		(mid 341.825457 -268.00428)
		(end 341.55126 -268.080236)
		(width 0.088646)
		(layer "In6.Cu")
		(net "M_C_CPU0_SA_DQ<15>")
	)
	(arc
		(start 342.49106 -268.080236)
		(mid 342.303862 -268.130379)
		(end 342.116664 -268.080236)
		(width 0.088646)
		(layer "In6.Cu")
		(net "M_C_CPU0_SA_DQ<15>")
	)
	(arc
		(start 339.28685 -268.07414)
		(mid 339.008672 -268.004417)
		(end 338.732114 -268.080236)
		(width 0.088646)
		(layer "In6.Cu")
		(net "M_C_CPU0_SA_DQ<15>")
	)
	(arc
		(start 336.477864 -268.080236)
		(mid 336.195162 -268.00446)
		(end 335.91246 -268.080236)
		(width 0.088646)
		(layer "In6.Cu")
		(net "M_C_CPU0_SA_DQ<15>")
	)
	(segment
		(start 280.689558 -300.211236)
		(end 280.689558 -299.885608)
		(width 0.20066)
		(layer "F.Cu")
		(net "M_C_CPU0_SA_DQ<14>")
	)
	(segment
		(start 280.545794 -299.741844)
		(end 279.912826 -299.741844)
		(width 0.20066)
		(layer "F.Cu")
		(net "M_C_CPU0_SA_DQ<14>")
	)
	(segment
		(start 281.497278 -300.166786)
		(end 281.285442 -300.378622)
		(width 0.20066)
		(layer "F.Cu")
		(net "M_C_CPU0_SA_DQ<14>")
	)
	(segment
		(start 276.415246 -300.166786)
		(end 275.268182 -300.166786)
		(width 0.20066)
		(layer "F.Cu")
		(net "M_C_CPU0_SA_DQ<14>")
	)
	(segment
		(start 277.852886 -299.741844)
		(end 277.59787 -299.741844)
		(width 0.101854)
		(layer "F.Cu")
		(net "M_C_CPU0_SA_DQ<14>")
	)
	(segment
		(start 282.811982 -300.166786)
		(end 281.497278 -300.166786)
		(width 0.20066)
		(layer "F.Cu")
		(net "M_C_CPU0_SA_DQ<14>")
	)
	(segment
		(start 280.689558 -299.885608)
		(end 280.545794 -299.741844)
		(width 0.20066)
		(layer "F.Cu")
		(net "M_C_CPU0_SA_DQ<14>")
	)
	(segment
		(start 280.856944 -300.378622)
		(end 280.689558 -300.211236)
		(width 0.20066)
		(layer "F.Cu")
		(net "M_C_CPU0_SA_DQ<14>")
	)
	(segment
		(start 345.123262 -268.847824)
		(end 345.123262 -269.38351)
		(width 0.20066)
		(layer "F.Cu")
		(net "M_C_CPU0_SA_DQ<14>")
	)
	(segment
		(start 279.912826 -299.741844)
		(end 277.852886 -299.741844)
		(width 0.1016)
		(layer "F.Cu")
		(net "M_C_CPU0_SA_DQ<14>")
	)
	(segment
		(start 281.285442 -300.378622)
		(end 280.856944 -300.378622)
		(width 0.20066)
		(layer "F.Cu")
		(net "M_C_CPU0_SA_DQ<14>")
	)
	(segment
		(start 277.58771 -299.731684)
		(end 276.850348 -299.731684)
		(width 0.20066)
		(layer "F.Cu")
		(net "M_C_CPU0_SA_DQ<14>")
	)
	(segment
		(start 283.916882 -300.166786)
		(end 282.811982 -300.166786)
		(width 0.20066)
		(layer "F.Cu")
		(net "M_C_CPU0_SA_DQ<14>")
	)
	(segment
		(start 345.123516 -268.84757)
		(end 345.123262 -268.847824)
		(width 0.20066)
		(layer "F.Cu")
		(net "M_C_CPU0_SA_DQ<14>")
	)
	(segment
		(start 277.59787 -299.741844)
		(end 277.58771 -299.731684)
		(width 0.101854)
		(layer "F.Cu")
		(net "M_C_CPU0_SA_DQ<14>")
	)
	(segment
		(start 276.850348 -299.731684)
		(end 276.415246 -300.166786)
		(width 0.20066)
		(layer "F.Cu")
		(net "M_C_CPU0_SA_DQ<14>")
	)
	(segment
		(start 297.053762 -290.391596)
		(end 296.654728 -290.391596)
		(width 0.18288)
		(layer "In6.Cu")
		(net "M_C_CPU0_SA_DQ<14>")
	)
	(segment
		(start 294.35679 -290.391596)
		(end 294.050974 -290.697412)
		(width 0.18288)
		(layer "In6.Cu")
		(net "M_C_CPU0_SA_DQ<14>")
	)
	(segment
		(start 304.460656 -287.130744)
		(end 303.629568 -287.130744)
		(width 0.18288)
		(layer "In6.Cu")
		(net "M_C_CPU0_SA_DQ<14>")
	)
	(segment
		(start 290.691824 -292.193726)
		(end 290.531804 -292.033706)
		(width 0.18288)
		(layer "In6.Cu")
		(net "M_C_CPU0_SA_DQ<14>")
	)
	(segment
		(start 342.031828 -268.887956)
		(end 342.021414 -268.894052)
		(width 0.088646)
		(layer "In6.Cu")
		(net "M_C_CPU0_SA_DQ<14>")
	)
	(segment
		(start 286.758634 -296.138092)
		(end 286.941514 -296.320972)
		(width 0.18288)
		(layer "In6.Cu")
		(net "M_C_CPU0_SA_DQ<14>")
	)
	(segment
		(start 296.654728 -290.391596)
		(end 296.348912 -290.697412)
		(width 0.18288)
		(layer "In6.Cu")
		(net "M_C_CPU0_SA_DQ<14>")
	)
	(segment
		(start 330.504546 -271.964658)
		(end 322.744592 -275.179028)
		(width 0.18288)
		(layer "In6.Cu")
		(net "M_C_CPU0_SA_DQ<14>")
	)
	(segment
		(start 286.360362 -296.138092)
		(end 286.758634 -296.138092)
		(width 0.18288)
		(layer "In6.Cu")
		(net "M_C_CPU0_SA_DQ<14>")
	)
	(segment
		(start 286.177482 -298.393612)
		(end 286.177482 -299.098716)
		(width 0.18288)
		(layer "In6.Cu")
		(net "M_C_CPU0_SA_DQ<14>")
	)
	(segment
		(start 322.744592 -275.179028)
		(end 315.043058 -282.880562)
		(width 0.18288)
		(layer "In6.Cu")
		(net "M_C_CPU0_SA_DQ<14>")
	)
	(segment
		(start 331.516228 -271.964658)
		(end 331.283056 -271.964658)
		(width 0.088646)
		(layer "In6.Cu")
		(net "M_C_CPU0_SA_DQ<14>")
	)
	(segment
		(start 296.348912 -290.697412)
		(end 295.961308 -290.697412)
		(width 0.18288)
		(layer "In6.Cu")
		(net "M_C_CPU0_SA_DQ<14>")
	)
	(segment
		(start 293.043864 -290.391596)
		(end 292.893496 -290.241228)
		(width 0.18288)
		(layer "In6.Cu")
		(net "M_C_CPU0_SA_DQ<14>")
	)
	(segment
		(start 292.289738 -291.298122)
		(end 292.289738 -291.55009)
		(width 0.18288)
		(layer "In6.Cu")
		(net "M_C_CPU0_SA_DQ<14>")
	)
	(segment
		(start 315.043058 -282.880562)
		(end 313.509406 -282.880562)
		(width 0.18288)
		(layer "In6.Cu")
		(net "M_C_CPU0_SA_DQ<14>")
	)
	(segment
		(start 294.050974 -290.697412)
		(end 293.66337 -290.697412)
		(width 0.18288)
		(layer "In6.Cu")
		(net "M_C_CPU0_SA_DQ<14>")
	)
	(segment
		(start 288.393886 -293.203884)
		(end 288.53511 -293.345108)
		(width 0.18288)
		(layer "In6.Cu")
		(net "M_C_CPU0_SA_DQ<14>")
	)
	(segment
		(start 288.62401 -292.715188)
		(end 288.393886 -292.945312)
		(width 0.18288)
		(layer "In6.Cu")
		(net "M_C_CPU0_SA_DQ<14>")
	)
	(segment
		(start 331.786738 -271.694148)
		(end 331.516228 -271.964658)
		(width 0.088646)
		(layer "In6.Cu")
		(net "M_C_CPU0_SA_DQ<14>")
	)
	(segment
		(start 344.56497 -268.951964)
		(end 344.481912 -268.903196)
		(width 0.088646)
		(layer "In6.Cu")
		(net "M_C_CPU0_SA_DQ<14>")
	)
	(segment
		(start 286.758634 -298.210732)
		(end 286.360362 -298.210732)
		(width 0.18288)
		(layer "In6.Cu")
		(net "M_C_CPU0_SA_DQ<14>")
	)
	(segment
		(start 306.166774 -285.424626)
		(end 304.460656 -287.130744)
		(width 0.18288)
		(layer "In6.Cu")
		(net "M_C_CPU0_SA_DQ<14>")
	)
	(segment
		(start 295.655492 -290.391596)
		(end 294.35679 -290.391596)
		(width 0.18288)
		(layer "In6.Cu")
		(net "M_C_CPU0_SA_DQ<14>")
	)
	(segment
		(start 286.758634 -297.519852)
		(end 286.941514 -297.702732)
		(width 0.18288)
		(layer "In6.Cu")
		(net "M_C_CPU0_SA_DQ<14>")
	)
	(segment
		(start 284.507178 -299.57649)
		(end 283.916882 -300.166786)
		(width 0.18288)
		(layer "In6.Cu")
		(net "M_C_CPU0_SA_DQ<14>")
	)
	(segment
		(start 289.831526 -292.30701)
		(end 289.282378 -292.856158)
		(width 0.18288)
		(layer "In6.Cu")
		(net "M_C_CPU0_SA_DQ<14>")
	)
	(segment
		(start 289.831526 -291.746178)
		(end 289.831526 -292.30701)
		(width 0.18288)
		(layer "In6.Cu")
		(net "M_C_CPU0_SA_DQ<14>")
	)
	(segment
		(start 286.758634 -296.828972)
		(end 286.360362 -296.828972)
		(width 0.18288)
		(layer "In6.Cu")
		(net "M_C_CPU0_SA_DQ<14>")
	)
	(segment
		(start 285.699708 -299.57649)
		(end 284.507178 -299.57649)
		(width 0.18288)
		(layer "In6.Cu")
		(net "M_C_CPU0_SA_DQ<14>")
	)
	(segment
		(start 300.584362 -289.541458)
		(end 297.9039 -289.541458)
		(width 0.18288)
		(layer "In6.Cu")
		(net "M_C_CPU0_SA_DQ<14>")
	)
	(segment
		(start 286.360362 -296.828972)
		(end 286.177482 -297.011852)
		(width 0.18288)
		(layer "In6.Cu")
		(net "M_C_CPU0_SA_DQ<14>")
	)
	(segment
		(start 295.961308 -290.697412)
		(end 295.655492 -290.391596)
		(width 0.18288)
		(layer "In6.Cu")
		(net "M_C_CPU0_SA_DQ<14>")
	)
	(segment
		(start 292.289738 -291.55009)
		(end 291.646102 -292.193726)
		(width 0.18288)
		(layer "In6.Cu")
		(net "M_C_CPU0_SA_DQ<14>")
	)
	(segment
		(start 293.357554 -290.391596)
		(end 293.043864 -290.391596)
		(width 0.18288)
		(layer "In6.Cu")
		(net "M_C_CPU0_SA_DQ<14>")
	)
	(segment
		(start 286.941514 -297.702732)
		(end 286.941514 -298.027852)
		(width 0.18288)
		(layer "In6.Cu")
		(net "M_C_CPU0_SA_DQ<14>")
	)
	(segment
		(start 292.051486 -290.83381)
		(end 292.051486 -291.05987)
		(width 0.18288)
		(layer "In6.Cu")
		(net "M_C_CPU0_SA_DQ<14>")
	)
	(segment
		(start 307.680614 -284.695646)
		(end 306.951634 -285.424626)
		(width 0.18288)
		(layer "In6.Cu")
		(net "M_C_CPU0_SA_DQ<14>")
	)
	(segment
		(start 286.940752 -294.092884)
		(end 286.177482 -294.856154)
		(width 0.18288)
		(layer "In6.Cu")
		(net "M_C_CPU0_SA_DQ<14>")
	)
	(segment
		(start 306.951634 -285.424626)
		(end 306.166774 -285.424626)
		(width 0.18288)
		(layer "In6.Cu")
		(net "M_C_CPU0_SA_DQ<14>")
	)
	(segment
		(start 290.531804 -292.033706)
		(end 290.531804 -291.71392)
		(width 0.18288)
		(layer "In6.Cu")
		(net "M_C_CPU0_SA_DQ<14>")
	)
	(segment
		(start 303.629568 -287.130744)
		(end 302.736504 -288.023808)
		(width 0.18288)
		(layer "In6.Cu")
		(net "M_C_CPU0_SA_DQ<14>")
	)
	(segment
		(start 292.893496 -290.241228)
		(end 292.644068 -290.241228)
		(width 0.18288)
		(layer "In6.Cu")
		(net "M_C_CPU0_SA_DQ<14>")
	)
	(segment
		(start 341.096346 -268.885416)
		(end 341.081614 -268.894052)
		(width 0.088646)
		(layer "In6.Cu")
		(net "M_C_CPU0_SA_DQ<14>")
	)
	(segment
		(start 313.509406 -282.880562)
		(end 312.97118 -283.418788)
		(width 0.18288)
		(layer "In6.Cu")
		(net "M_C_CPU0_SA_DQ<14>")
	)
	(segment
		(start 290.371784 -291.5539)
		(end 290.023804 -291.5539)
		(width 0.18288)
		(layer "In6.Cu")
		(net "M_C_CPU0_SA_DQ<14>")
	)
	(segment
		(start 333.915766 -269.797784)
		(end 333.73187 -269.98168)
		(width 0.088646)
		(layer "In6.Cu")
		(net "M_C_CPU0_SA_DQ<14>")
	)
	(segment
		(start 302.736504 -288.023808)
		(end 302.102012 -288.023808)
		(width 0.18288)
		(layer "In6.Cu")
		(net "M_C_CPU0_SA_DQ<14>")
	)
	(segment
		(start 286.177482 -299.098716)
		(end 285.699708 -299.57649)
		(width 0.18288)
		(layer "In6.Cu")
		(net "M_C_CPU0_SA_DQ<14>")
	)
	(segment
		(start 334.220312 -269.373604)
		(end 334.220312 -269.38351)
		(width 0.088646)
		(layer "In6.Cu")
		(net "M_C_CPU0_SA_DQ<14>")
	)
	(segment
		(start 290.023804 -291.5539)
		(end 289.831526 -291.746178)
		(width 0.18288)
		(layer "In6.Cu")
		(net "M_C_CPU0_SA_DQ<14>")
	)
	(segment
		(start 311.784492 -283.418788)
		(end 310.507634 -284.695646)
		(width 0.18288)
		(layer "In6.Cu")
		(net "M_C_CPU0_SA_DQ<14>")
	)
	(segment
		(start 297.9039 -289.541458)
		(end 297.053762 -290.391596)
		(width 0.18288)
		(layer "In6.Cu")
		(net "M_C_CPU0_SA_DQ<14>")
	)
	(segment
		(start 333.73187 -269.98168)
		(end 333.378048 -269.98168)
		(width 0.088646)
		(layer "In6.Cu")
		(net "M_C_CPU0_SA_DQ<14>")
	)
	(segment
		(start 345.123262 -269.38351)
		(end 344.56497 -268.951964)
		(width 0.088646)
		(layer "In6.Cu")
		(net "M_C_CPU0_SA_DQ<14>")
	)
	(segment
		(start 332.934056 -270.425672)
		(end 332.673706 -270.425672)
		(width 0.088646)
		(layer "In6.Cu")
		(net "M_C_CPU0_SA_DQ<14>")
	)
	(segment
		(start 331.283056 -271.964658)
		(end 330.504546 -271.964658)
		(width 0.18288)
		(layer "In6.Cu")
		(net "M_C_CPU0_SA_DQ<14>")
	)
	(segment
		(start 289.023806 -292.856412)
		(end 288.882582 -292.715188)
		(width 0.18288)
		(layer "In6.Cu")
		(net "M_C_CPU0_SA_DQ<14>")
	)
	(segment
		(start 312.97118 -283.418788)
		(end 311.784492 -283.418788)
		(width 0.18288)
		(layer "In6.Cu")
		(net "M_C_CPU0_SA_DQ<14>")
	)
	(segment
		(start 291.646102 -292.193726)
		(end 290.691824 -292.193726)
		(width 0.18288)
		(layer "In6.Cu")
		(net "M_C_CPU0_SA_DQ<14>")
	)
	(segment
		(start 288.393886 -292.945312)
		(end 288.393886 -293.203884)
		(width 0.18288)
		(layer "In6.Cu")
		(net "M_C_CPU0_SA_DQ<14>")
	)
	(segment
		(start 292.644068 -290.241228)
		(end 292.051486 -290.83381)
		(width 0.18288)
		(layer "In6.Cu")
		(net "M_C_CPU0_SA_DQ<14>")
	)
	(segment
		(start 293.66337 -290.697412)
		(end 293.357554 -290.391596)
		(width 0.18288)
		(layer "In6.Cu")
		(net "M_C_CPU0_SA_DQ<14>")
	)
	(segment
		(start 288.882582 -292.715188)
		(end 288.62401 -292.715188)
		(width 0.18288)
		(layer "In6.Cu")
		(net "M_C_CPU0_SA_DQ<14>")
	)
	(segment
		(start 290.531804 -291.71392)
		(end 290.371784 -291.5539)
		(width 0.18288)
		(layer "In6.Cu")
		(net "M_C_CPU0_SA_DQ<14>")
	)
	(segment
		(start 286.941514 -296.646092)
		(end 286.758634 -296.828972)
		(width 0.18288)
		(layer "In6.Cu")
		(net "M_C_CPU0_SA_DQ<14>")
	)
	(segment
		(start 286.360362 -297.519852)
		(end 286.758634 -297.519852)
		(width 0.18288)
		(layer "In6.Cu")
		(net "M_C_CPU0_SA_DQ<14>")
	)
	(segment
		(start 333.378048 -269.98168)
		(end 332.934056 -270.425672)
		(width 0.088646)
		(layer "In6.Cu")
		(net "M_C_CPU0_SA_DQ<14>")
	)
	(segment
		(start 332.673706 -270.425672)
		(end 331.786738 -271.31264)
		(width 0.088646)
		(layer "In6.Cu")
		(net "M_C_CPU0_SA_DQ<14>")
	)
	(segment
		(start 343.537286 -268.900402)
		(end 343.511632 -268.885416)
		(width 0.088646)
		(layer "In6.Cu")
		(net "M_C_CPU0_SA_DQ<14>")
	)
	(segment
		(start 286.177482 -295.955212)
		(end 286.360362 -296.138092)
		(width 0.18288)
		(layer "In6.Cu")
		(net "M_C_CPU0_SA_DQ<14>")
	)
	(segment
		(start 286.941514 -298.027852)
		(end 286.758634 -298.210732)
		(width 0.18288)
		(layer "In6.Cu")
		(net "M_C_CPU0_SA_DQ<14>")
	)
	(segment
		(start 340.156546 -268.885416)
		(end 340.141814 -268.894052)
		(width 0.088646)
		(layer "In6.Cu")
		(net "M_C_CPU0_SA_DQ<14>")
	)
	(segment
		(start 302.102012 -288.023808)
		(end 300.584362 -289.541458)
		(width 0.18288)
		(layer "In6.Cu")
		(net "M_C_CPU0_SA_DQ<14>")
	)
	(segment
		(start 288.045652 -294.092884)
		(end 286.940752 -294.092884)
		(width 0.18288)
		(layer "In6.Cu")
		(net "M_C_CPU0_SA_DQ<14>")
	)
	(segment
		(start 292.051486 -291.05987)
		(end 292.289738 -291.298122)
		(width 0.18288)
		(layer "In6.Cu")
		(net "M_C_CPU0_SA_DQ<14>")
	)
	(segment
		(start 286.177482 -297.011852)
		(end 286.177482 -297.336972)
		(width 0.18288)
		(layer "In6.Cu")
		(net "M_C_CPU0_SA_DQ<14>")
	)
	(segment
		(start 288.53511 -293.345108)
		(end 288.53511 -293.603426)
		(width 0.18288)
		(layer "In6.Cu")
		(net "M_C_CPU0_SA_DQ<14>")
	)
	(segment
		(start 331.786738 -271.31264)
		(end 331.786738 -271.694148)
		(width 0.088646)
		(layer "In6.Cu")
		(net "M_C_CPU0_SA_DQ<14>")
	)
	(segment
		(start 310.507634 -284.695646)
		(end 307.680614 -284.695646)
		(width 0.18288)
		(layer "In6.Cu")
		(net "M_C_CPU0_SA_DQ<14>")
	)
	(segment
		(start 338.272374 -268.887956)
		(end 338.26196 -268.894052)
		(width 0.088646)
		(layer "In6.Cu")
		(net "M_C_CPU0_SA_DQ<14>")
	)
	(segment
		(start 286.177482 -297.336972)
		(end 286.360362 -297.519852)
		(width 0.18288)
		(layer "In6.Cu")
		(net "M_C_CPU0_SA_DQ<14>")
	)
	(segment
		(start 286.177482 -294.856154)
		(end 286.177482 -295.955212)
		(width 0.18288)
		(layer "In6.Cu")
		(net "M_C_CPU0_SA_DQ<14>")
	)
	(segment
		(start 288.53511 -293.603426)
		(end 288.045652 -294.092884)
		(width 0.18288)
		(layer "In6.Cu")
		(net "M_C_CPU0_SA_DQ<14>")
	)
	(segment
		(start 286.941514 -296.320972)
		(end 286.941514 -296.646092)
		(width 0.18288)
		(layer "In6.Cu")
		(net "M_C_CPU0_SA_DQ<14>")
	)
	(segment
		(start 286.360362 -298.210732)
		(end 286.177482 -298.393612)
		(width 0.18288)
		(layer "In6.Cu")
		(net "M_C_CPU0_SA_DQ<14>")
	)
	(segment
		(start 289.282378 -292.856158)
		(end 289.023806 -292.856412)
		(width 0.18288)
		(layer "In6.Cu")
		(net "M_C_CPU0_SA_DQ<14>")
	)
	(arc
		(start 335.068164 -268.894052)
		(mid 334.785462 -268.818276)
		(end 334.50276 -268.894052)
		(width 0.088646)
		(layer "In6.Cu")
		(net "M_C_CPU0_SA_DQ<14>")
	)
	(arc
		(start 342.021414 -268.894052)
		(mid 341.834216 -268.944195)
		(end 341.647018 -268.894052)
		(width 0.088646)
		(layer "In6.Cu")
		(net "M_C_CPU0_SA_DQ<14>")
	)
	(arc
		(start 341.081614 -268.894052)
		(mid 340.894416 -268.944195)
		(end 340.707218 -268.894052)
		(width 0.088646)
		(layer "In6.Cu")
		(net "M_C_CPU0_SA_DQ<14>")
	)
	(arc
		(start 336.38236 -268.894052)
		(mid 336.195162 -268.944195)
		(end 336.007964 -268.894052)
		(width 0.088646)
		(layer "In6.Cu")
		(net "M_C_CPU0_SA_DQ<14>")
	)
	(arc
		(start 334.220312 -269.38351)
		(mid 334.172633 -269.56641)
		(end 334.04175 -269.702788)
		(width 0.088646)
		(layer "In6.Cu")
		(net "M_C_CPU0_SA_DQ<14>")
	)
	(arc
		(start 340.141814 -268.894052)
		(mid 339.954616 -268.944195)
		(end 339.767418 -268.894052)
		(width 0.088646)
		(layer "In6.Cu")
		(net "M_C_CPU0_SA_DQ<14>")
	)
	(arc
		(start 334.50276 -268.894052)
		(mid 334.298425 -269.096657)
		(end 334.220312 -269.373604)
		(width 0.088646)
		(layer "In6.Cu")
		(net "M_C_CPU0_SA_DQ<14>")
	)
	(arc
		(start 338.827618 -268.894052)
		(mid 338.550805 -268.818182)
		(end 338.272374 -268.887956)
		(width 0.088646)
		(layer "In6.Cu")
		(net "M_C_CPU0_SA_DQ<14>")
	)
	(arc
		(start 336.947764 -268.894052)
		(mid 336.665062 -268.818276)
		(end 336.38236 -268.894052)
		(width 0.088646)
		(layer "In6.Cu")
		(net "M_C_CPU0_SA_DQ<14>")
	)
	(arc
		(start 341.647018 -268.894052)
		(mid 341.372819 -268.818217)
		(end 341.096346 -268.885416)
		(width 0.088646)
		(layer "In6.Cu")
		(net "M_C_CPU0_SA_DQ<14>")
	)
	(arc
		(start 336.007964 -268.894052)
		(mid 335.725262 -268.818276)
		(end 335.44256 -268.894052)
		(width 0.088646)
		(layer "In6.Cu")
		(net "M_C_CPU0_SA_DQ<14>")
	)
	(arc
		(start 344.481912 -268.903196)
		(mid 344.197643 -268.825683)
		(end 343.912952 -268.901672)
		(width 0.088646)
		(layer "In6.Cu")
		(net "M_C_CPU0_SA_DQ<14>")
	)
	(arc
		(start 339.767418 -268.894052)
		(mid 339.484716 -268.818276)
		(end 339.202014 -268.894052)
		(width 0.088646)
		(layer "In6.Cu")
		(net "M_C_CPU0_SA_DQ<14>")
	)
	(arc
		(start 337.32216 -268.894052)
		(mid 337.134962 -268.944195)
		(end 336.947764 -268.894052)
		(width 0.088646)
		(layer "In6.Cu")
		(net "M_C_CPU0_SA_DQ<14>")
	)
	(arc
		(start 337.887564 -268.894052)
		(mid 337.604862 -268.818276)
		(end 337.32216 -268.894052)
		(width 0.088646)
		(layer "In6.Cu")
		(net "M_C_CPU0_SA_DQ<14>")
	)
	(arc
		(start 342.586564 -268.894052)
		(mid 342.310005 -268.818309)
		(end 342.031828 -268.887956)
		(width 0.088646)
		(layer "In6.Cu")
		(net "M_C_CPU0_SA_DQ<14>")
	)
	(arc
		(start 338.26196 -268.894052)
		(mid 338.074762 -268.944195)
		(end 337.887564 -268.894052)
		(width 0.088646)
		(layer "In6.Cu")
		(net "M_C_CPU0_SA_DQ<14>")
	)
	(arc
		(start 334.04175 -269.702788)
		(mid 333.975426 -269.745868)
		(end 333.915766 -269.797784)
		(width 0.088646)
		(layer "In6.Cu")
		(net "M_C_CPU0_SA_DQ<14>")
	)
	(arc
		(start 342.96096 -268.894052)
		(mid 342.773762 -268.944195)
		(end 342.586564 -268.894052)
		(width 0.088646)
		(layer "In6.Cu")
		(net "M_C_CPU0_SA_DQ<14>")
	)
	(arc
		(start 343.912952 -268.901672)
		(mid 343.724955 -268.951661)
		(end 343.537286 -268.900402)
		(width 0.088646)
		(layer "In6.Cu")
		(net "M_C_CPU0_SA_DQ<14>")
	)
	(arc
		(start 343.511632 -268.885416)
		(mid 343.235157 -268.818096)
		(end 342.96096 -268.894052)
		(width 0.088646)
		(layer "In6.Cu")
		(net "M_C_CPU0_SA_DQ<14>")
	)
	(arc
		(start 339.202014 -268.894052)
		(mid 339.014816 -268.944195)
		(end 338.827618 -268.894052)
		(width 0.088646)
		(layer "In6.Cu")
		(net "M_C_CPU0_SA_DQ<14>")
	)
	(arc
		(start 335.44256 -268.894052)
		(mid 335.255362 -268.944195)
		(end 335.068164 -268.894052)
		(width 0.088646)
		(layer "In6.Cu")
		(net "M_C_CPU0_SA_DQ<14>")
	)
	(arc
		(start 340.707218 -268.894052)
		(mid 340.433019 -268.818217)
		(end 340.156546 -268.885416)
		(width 0.088646)
		(layer "In6.Cu")
		(net "M_C_CPU0_SA_DQ<14>")
	)
	(segment
		(start 274.152868 -298.891706)
		(end 274.143978 -298.882816)
		(width 0.1016)
		(layer "F.Cu")
		(net "M_C_CPU0_SA_DQ<13>")
	)
	(segment
		(start 273.218148 -299.527976)
		(end 272.713704 -299.527976)
		(width 0.20066)
		(layer "F.Cu")
		(net "M_C_CPU0_SA_DQ<13>")
	)
	(segment
		(start 276.647656 -298.891706)
		(end 276.469094 -298.891706)
		(width 0.20066)
		(layer "F.Cu")
		(net "M_C_CPU0_SA_DQ<13>")
	)
	(segment
		(start 279.816814 -299.316648)
		(end 278.711914 -299.316648)
		(width 0.20066)
		(layer "F.Cu")
		(net "M_C_CPU0_SA_DQ<13>")
	)
	(segment
		(start 276.469094 -298.891706)
		(end 276.138386 -298.891706)
		(width 0.101854)
		(layer "F.Cu")
		(net "M_C_CPU0_SA_DQ<13>")
	)
	(segment
		(start 278.711914 -299.316648)
		(end 277.072598 -299.316648)
		(width 0.20066)
		(layer "F.Cu")
		(net "M_C_CPU0_SA_DQ<13>")
	)
	(segment
		(start 343.713562 -268.033754)
		(end 343.713816 -268.034008)
		(width 0.20066)
		(layer "F.Cu")
		(net "M_C_CPU0_SA_DQ<13>")
	)
	(segment
		(start 273.53514 -298.882816)
		(end 273.37258 -299.045376)
		(width 0.20066)
		(layer "F.Cu")
		(net "M_C_CPU0_SA_DQ<13>")
	)
	(segment
		(start 274.143978 -298.882816)
		(end 273.53514 -298.882816)
		(width 0.20066)
		(layer "F.Cu")
		(net "M_C_CPU0_SA_DQ<13>")
	)
	(segment
		(start 273.37258 -299.045376)
		(end 273.37258 -299.373544)
		(width 0.20066)
		(layer "F.Cu")
		(net "M_C_CPU0_SA_DQ<13>")
	)
	(segment
		(start 272.713704 -299.527976)
		(end 272.502376 -299.316648)
		(width 0.20066)
		(layer "F.Cu")
		(net "M_C_CPU0_SA_DQ<13>")
	)
	(segment
		(start 277.072598 -299.316648)
		(end 276.647656 -298.891706)
		(width 0.20066)
		(layer "F.Cu")
		(net "M_C_CPU0_SA_DQ<13>")
	)
	(segment
		(start 343.713816 -268.034008)
		(end 343.713816 -268.569694)
		(width 0.20066)
		(layer "F.Cu")
		(net "M_C_CPU0_SA_DQ<13>")
	)
	(segment
		(start 276.138386 -298.891706)
		(end 274.152868 -298.891706)
		(width 0.1016)
		(layer "F.Cu")
		(net "M_C_CPU0_SA_DQ<13>")
	)
	(segment
		(start 273.37258 -299.373544)
		(end 273.218148 -299.527976)
		(width 0.20066)
		(layer "F.Cu")
		(net "M_C_CPU0_SA_DQ<13>")
	)
	(segment
		(start 272.502376 -299.316648)
		(end 271.168114 -299.316648)
		(width 0.20066)
		(layer "F.Cu")
		(net "M_C_CPU0_SA_DQ<13>")
	)
	(segment
		(start 313.544458 -282.37942)
		(end 312.876184 -282.37942)
		(width 0.18288)
		(layer "In6.Cu")
		(net "M_C_CPU0_SA_DQ<13>")
	)
	(segment
		(start 281.62377 -298.104814)
		(end 281.29865 -298.104814)
		(width 0.18288)
		(layer "In6.Cu")
		(net "M_C_CPU0_SA_DQ<13>")
	)
	(segment
		(start 284.197298 -298.891452)
		(end 284.197044 -298.891706)
		(width 0.18288)
		(layer "In6.Cu")
		(net "M_C_CPU0_SA_DQ<13>")
	)
	(segment
		(start 310.337454 -284.154626)
		(end 306.474622 -284.154626)
		(width 0.18288)
		(layer "In6.Cu")
		(net "M_C_CPU0_SA_DQ<13>")
	)
	(segment
		(start 287.453578 -293.14267)
		(end 286.979106 -293.14267)
		(width 0.18288)
		(layer "In6.Cu")
		(net "M_C_CPU0_SA_DQ<13>")
	)
	(segment
		(start 281.11577 -298.287694)
		(end 281.11577 -298.708572)
		(width 0.18288)
		(layer "In6.Cu")
		(net "M_C_CPU0_SA_DQ<13>")
	)
	(segment
		(start 280.93289 -298.891452)
		(end 280.24201 -298.891452)
		(width 0.18288)
		(layer "In6.Cu")
		(net "M_C_CPU0_SA_DQ<13>")
	)
	(segment
		(start 342.971374 -268.251432)
		(end 342.96096 -268.245336)
		(width 0.088646)
		(layer "In6.Cu")
		(net "M_C_CPU0_SA_DQ<13>")
	)
	(segment
		(start 303.567592 -286.016954)
		(end 302.726598 -286.857948)
		(width 0.18288)
		(layer "In6.Cu")
		(net "M_C_CPU0_SA_DQ<13>")
	)
	(segment
		(start 288.252408 -291.860224)
		(end 288.252408 -292.34384)
		(width 0.18288)
		(layer "In6.Cu")
		(net "M_C_CPU0_SA_DQ<13>")
	)
	(segment
		(start 344.02649 -268.569694)
		(end 344.083894 -268.51229)
		(width 0.088646)
		(layer "In6.Cu")
		(net "M_C_CPU0_SA_DQ<13>")
	)
	(segment
		(start 283.719016 -298.891706)
		(end 283.718762 -298.891452)
		(width 0.18288)
		(layer "In6.Cu")
		(net "M_C_CPU0_SA_DQ<13>")
	)
	(segment
		(start 322.363592 -274.796758)
		(end 315.4045 -281.75585)
		(width 0.18288)
		(layer "In6.Cu")
		(net "M_C_CPU0_SA_DQ<13>")
	)
	(segment
		(start 296.925746 -289.541712)
		(end 292.561772 -289.541712)
		(width 0.18288)
		(layer "In6.Cu")
		(net "M_C_CPU0_SA_DQ<13>")
	)
	(segment
		(start 343.909904 -268.250416)
		(end 343.901014 -268.245336)
		(width 0.088646)
		(layer "In6.Cu")
		(net "M_C_CPU0_SA_DQ<13>")
	)
	(segment
		(start 332.327758 -270.461994)
		(end 331.583792 -271.20596)
		(width 0.088646)
		(layer "In6.Cu")
		(net "M_C_CPU0_SA_DQ<13>")
	)
	(segment
		(start 331.583792 -271.20596)
		(end 331.583792 -271.346422)
		(width 0.088646)
		(layer "In6.Cu")
		(net "M_C_CPU0_SA_DQ<13>")
	)
	(segment
		(start 340.156546 -268.253972)
		(end 340.141814 -268.245336)
		(width 0.088646)
		(layer "In6.Cu")
		(net "M_C_CPU0_SA_DQ<13>")
	)
	(segment
		(start 288.252408 -292.34384)
		(end 287.453578 -293.14267)
		(width 0.18288)
		(layer "In6.Cu")
		(net "M_C_CPU0_SA_DQ<13>")
	)
	(segment
		(start 280.24201 -298.891452)
		(end 279.816814 -299.316648)
		(width 0.18288)
		(layer "In6.Cu")
		(net "M_C_CPU0_SA_DQ<13>")
	)
	(segment
		(start 333.940912 -268.569694)
		(end 333.940912 -268.5796)
		(width 0.088646)
		(layer "In6.Cu")
		(net "M_C_CPU0_SA_DQ<13>")
	)
	(segment
		(start 302.726598 -286.857948)
		(end 302.266858 -286.857948)
		(width 0.18288)
		(layer "In6.Cu")
		(net "M_C_CPU0_SA_DQ<13>")
	)
	(segment
		(start 281.98953 -298.891452)
		(end 281.80665 -298.708572)
		(width 0.18288)
		(layer "In6.Cu")
		(net "M_C_CPU0_SA_DQ<13>")
	)
	(segment
		(start 297.775884 -288.691574)
		(end 296.925746 -289.541712)
		(width 0.18288)
		(layer "In6.Cu")
		(net "M_C_CPU0_SA_DQ<13>")
	)
	(segment
		(start 281.80665 -298.287694)
		(end 281.62377 -298.104814)
		(width 0.18288)
		(layer "In6.Cu")
		(net "M_C_CPU0_SA_DQ<13>")
	)
	(segment
		(start 285.421578 -298.891452)
		(end 284.197298 -298.891452)
		(width 0.18288)
		(layer "In6.Cu")
		(net "M_C_CPU0_SA_DQ<13>")
	)
	(segment
		(start 284.197044 -298.891706)
		(end 283.719016 -298.891706)
		(width 0.18288)
		(layer "In6.Cu")
		(net "M_C_CPU0_SA_DQ<13>")
	)
	(segment
		(start 302.266858 -286.857948)
		(end 300.433232 -288.691574)
		(width 0.18288)
		(layer "In6.Cu")
		(net "M_C_CPU0_SA_DQ<13>")
	)
	(segment
		(start 314.168028 -281.75585)
		(end 313.544458 -282.37942)
		(width 0.18288)
		(layer "In6.Cu")
		(net "M_C_CPU0_SA_DQ<13>")
	)
	(segment
		(start 343.713816 -268.569694)
		(end 344.02649 -268.569694)
		(width 0.088646)
		(layer "In6.Cu")
		(net "M_C_CPU0_SA_DQ<13>")
	)
	(segment
		(start 311.582054 -282.910026)
		(end 310.337454 -284.154626)
		(width 0.18288)
		(layer "In6.Cu")
		(net "M_C_CPU0_SA_DQ<13>")
	)
	(segment
		(start 338.827618 -268.245336)
		(end 338.817204 -268.251432)
		(width 0.088646)
		(layer "In6.Cu")
		(net "M_C_CPU0_SA_DQ<13>")
	)
	(segment
		(start 332.542642 -269.562326)
		(end 332.327758 -269.77721)
		(width 0.088646)
		(layer "In6.Cu")
		(net "M_C_CPU0_SA_DQ<13>")
	)
	(segment
		(start 285.604458 -294.517318)
		(end 285.604458 -298.708572)
		(width 0.18288)
		(layer "In6.Cu")
		(net "M_C_CPU0_SA_DQ<13>")
	)
	(segment
		(start 285.604458 -298.708572)
		(end 285.421578 -298.891452)
		(width 0.18288)
		(layer "In6.Cu")
		(net "M_C_CPU0_SA_DQ<13>")
	)
	(segment
		(start 281.11577 -298.708572)
		(end 280.93289 -298.891452)
		(width 0.18288)
		(layer "In6.Cu")
		(net "M_C_CPU0_SA_DQ<13>")
	)
	(segment
		(start 334.128364 -268.245336)
		(end 334.119474 -268.250416)
		(width 0.088646)
		(layer "In6.Cu")
		(net "M_C_CPU0_SA_DQ<13>")
	)
	(segment
		(start 306.474622 -284.154626)
		(end 304.612294 -286.016954)
		(width 0.18288)
		(layer "In6.Cu")
		(net "M_C_CPU0_SA_DQ<13>")
	)
	(segment
		(start 339.216746 -268.253972)
		(end 339.202014 -268.245336)
		(width 0.088646)
		(layer "In6.Cu")
		(net "M_C_CPU0_SA_DQ<13>")
	)
	(segment
		(start 331.495146 -271.435068)
		(end 331.283056 -271.435068)
		(width 0.088646)
		(layer "In6.Cu")
		(net "M_C_CPU0_SA_DQ<13>")
	)
	(segment
		(start 292.561772 -289.541712)
		(end 291.091366 -291.012118)
		(width 0.18288)
		(layer "In6.Cu")
		(net "M_C_CPU0_SA_DQ<13>")
	)
	(segment
		(start 330.48194 -271.435068)
		(end 322.363592 -274.796758)
		(width 0.18288)
		(layer "In6.Cu")
		(net "M_C_CPU0_SA_DQ<13>")
	)
	(segment
		(start 331.283056 -271.435068)
		(end 330.48194 -271.435068)
		(width 0.18288)
		(layer "In6.Cu")
		(net "M_C_CPU0_SA_DQ<13>")
	)
	(segment
		(start 283.718762 -298.891452)
		(end 281.98953 -298.891452)
		(width 0.18288)
		(layer "In6.Cu")
		(net "M_C_CPU0_SA_DQ<13>")
	)
	(segment
		(start 281.80665 -298.708572)
		(end 281.80665 -298.287694)
		(width 0.18288)
		(layer "In6.Cu")
		(net "M_C_CPU0_SA_DQ<13>")
	)
	(segment
		(start 291.091366 -291.012118)
		(end 289.100514 -291.012118)
		(width 0.18288)
		(layer "In6.Cu")
		(net "M_C_CPU0_SA_DQ<13>")
	)
	(segment
		(start 333.136494 -269.562326)
		(end 332.542642 -269.562326)
		(width 0.088646)
		(layer "In6.Cu")
		(net "M_C_CPU0_SA_DQ<13>")
	)
	(segment
		(start 341.096346 -268.253972)
		(end 341.081614 -268.245336)
		(width 0.088646)
		(layer "In6.Cu")
		(net "M_C_CPU0_SA_DQ<13>")
	)
	(segment
		(start 304.612294 -286.016954)
		(end 303.567592 -286.016954)
		(width 0.18288)
		(layer "In6.Cu")
		(net "M_C_CPU0_SA_DQ<13>")
	)
	(segment
		(start 289.100514 -291.012118)
		(end 288.252408 -291.860224)
		(width 0.18288)
		(layer "In6.Cu")
		(net "M_C_CPU0_SA_DQ<13>")
	)
	(segment
		(start 286.979106 -293.14267)
		(end 285.604458 -294.517318)
		(width 0.18288)
		(layer "In6.Cu")
		(net "M_C_CPU0_SA_DQ<13>")
	)
	(segment
		(start 300.433232 -288.691574)
		(end 297.775884 -288.691574)
		(width 0.18288)
		(layer "In6.Cu")
		(net "M_C_CPU0_SA_DQ<13>")
	)
	(segment
		(start 312.345578 -282.910026)
		(end 311.582054 -282.910026)
		(width 0.18288)
		(layer "In6.Cu")
		(net "M_C_CPU0_SA_DQ<13>")
	)
	(segment
		(start 315.4045 -281.75585)
		(end 314.168028 -281.75585)
		(width 0.18288)
		(layer "In6.Cu")
		(net "M_C_CPU0_SA_DQ<13>")
	)
	(segment
		(start 342.031828 -268.251432)
		(end 342.021414 -268.245336)
		(width 0.088646)
		(layer "In6.Cu")
		(net "M_C_CPU0_SA_DQ<13>")
	)
	(segment
		(start 312.876184 -282.37942)
		(end 312.345578 -282.910026)
		(width 0.18288)
		(layer "In6.Cu")
		(net "M_C_CPU0_SA_DQ<13>")
	)
	(segment
		(start 281.29865 -298.104814)
		(end 281.11577 -298.287694)
		(width 0.18288)
		(layer "In6.Cu")
		(net "M_C_CPU0_SA_DQ<13>")
	)
	(segment
		(start 331.583792 -271.346422)
		(end 331.495146 -271.435068)
		(width 0.088646)
		(layer "In6.Cu")
		(net "M_C_CPU0_SA_DQ<13>")
	)
	(segment
		(start 332.327758 -269.77721)
		(end 332.327758 -270.461994)
		(width 0.088646)
		(layer "In6.Cu")
		(net "M_C_CPU0_SA_DQ<13>")
	)
	(segment
		(start 333.580486 -269.118334)
		(end 333.136494 -269.562326)
		(width 0.088646)
		(layer "In6.Cu")
		(net "M_C_CPU0_SA_DQ<13>")
	)
	(arc
		(start 339.767418 -268.245336)
		(mid 339.493219 -268.321171)
		(end 339.216746 -268.253972)
		(width 0.088646)
		(layer "In6.Cu")
		(net "M_C_CPU0_SA_DQ<13>")
	)
	(arc
		(start 333.940912 -268.5796)
		(mid 333.862801 -268.856549)
		(end 333.658464 -269.059152)
		(width 0.088646)
		(layer "In6.Cu")
		(net "M_C_CPU0_SA_DQ<13>")
	)
	(arc
		(start 342.021414 -268.245336)
		(mid 341.834216 -268.195193)
		(end 341.647018 -268.245336)
		(width 0.088646)
		(layer "In6.Cu")
		(net "M_C_CPU0_SA_DQ<13>")
	)
	(arc
		(start 344.083894 -268.51229)
		(mid 344.025738 -268.362177)
		(end 343.909904 -268.250416)
		(width 0.088646)
		(layer "In6.Cu")
		(net "M_C_CPU0_SA_DQ<13>")
	)
	(arc
		(start 341.647018 -268.245336)
		(mid 341.372819 -268.321171)
		(end 341.096346 -268.253972)
		(width 0.088646)
		(layer "In6.Cu")
		(net "M_C_CPU0_SA_DQ<13>")
	)
	(arc
		(start 336.38236 -268.245336)
		(mid 336.195162 -268.195193)
		(end 336.007964 -268.245336)
		(width 0.088646)
		(layer "In6.Cu")
		(net "M_C_CPU0_SA_DQ<13>")
	)
	(arc
		(start 335.44256 -268.245336)
		(mid 335.255362 -268.195193)
		(end 335.068164 -268.245336)
		(width 0.088646)
		(layer "In6.Cu")
		(net "M_C_CPU0_SA_DQ<13>")
	)
	(arc
		(start 340.707218 -268.245336)
		(mid 340.433019 -268.321171)
		(end 340.156546 -268.253972)
		(width 0.088646)
		(layer "In6.Cu")
		(net "M_C_CPU0_SA_DQ<13>")
	)
	(arc
		(start 336.007964 -268.245336)
		(mid 335.725262 -268.321112)
		(end 335.44256 -268.245336)
		(width 0.088646)
		(layer "In6.Cu")
		(net "M_C_CPU0_SA_DQ<13>")
	)
	(arc
		(start 343.901014 -268.245336)
		(mid 343.713816 -268.195193)
		(end 343.526618 -268.245336)
		(width 0.088646)
		(layer "In6.Cu")
		(net "M_C_CPU0_SA_DQ<13>")
	)
	(arc
		(start 333.658464 -269.059152)
		(mid 333.617534 -269.086185)
		(end 333.580486 -269.118334)
		(width 0.088646)
		(layer "In6.Cu")
		(net "M_C_CPU0_SA_DQ<13>")
	)
	(arc
		(start 341.081614 -268.245336)
		(mid 340.894416 -268.195193)
		(end 340.707218 -268.245336)
		(width 0.088646)
		(layer "In6.Cu")
		(net "M_C_CPU0_SA_DQ<13>")
	)
	(arc
		(start 336.947764 -268.245336)
		(mid 336.665062 -268.321112)
		(end 336.38236 -268.245336)
		(width 0.088646)
		(layer "In6.Cu")
		(net "M_C_CPU0_SA_DQ<13>")
	)
	(arc
		(start 337.32216 -268.245336)
		(mid 337.134962 -268.195193)
		(end 336.947764 -268.245336)
		(width 0.088646)
		(layer "In6.Cu")
		(net "M_C_CPU0_SA_DQ<13>")
	)
	(arc
		(start 342.586564 -268.245336)
		(mid 342.310005 -268.321079)
		(end 342.031828 -268.251432)
		(width 0.088646)
		(layer "In6.Cu")
		(net "M_C_CPU0_SA_DQ<13>")
	)
	(arc
		(start 334.119474 -268.250416)
		(mid 333.98856 -268.386776)
		(end 333.940912 -268.569694)
		(width 0.088646)
		(layer "In6.Cu")
		(net "M_C_CPU0_SA_DQ<13>")
	)
	(arc
		(start 343.526618 -268.245336)
		(mid 343.249805 -268.321206)
		(end 342.971374 -268.251432)
		(width 0.088646)
		(layer "In6.Cu")
		(net "M_C_CPU0_SA_DQ<13>")
	)
	(arc
		(start 334.50276 -268.245336)
		(mid 334.315562 -268.195193)
		(end 334.128364 -268.245336)
		(width 0.088646)
		(layer "In6.Cu")
		(net "M_C_CPU0_SA_DQ<13>")
	)
	(arc
		(start 339.202014 -268.245336)
		(mid 339.014816 -268.195193)
		(end 338.827618 -268.245336)
		(width 0.088646)
		(layer "In6.Cu")
		(net "M_C_CPU0_SA_DQ<13>")
	)
	(arc
		(start 335.068164 -268.245336)
		(mid 334.785462 -268.321112)
		(end 334.50276 -268.245336)
		(width 0.088646)
		(layer "In6.Cu")
		(net "M_C_CPU0_SA_DQ<13>")
	)
	(arc
		(start 338.817204 -268.251432)
		(mid 338.538772 -268.321278)
		(end 338.26196 -268.245336)
		(width 0.088646)
		(layer "In6.Cu")
		(net "M_C_CPU0_SA_DQ<13>")
	)
	(arc
		(start 338.26196 -268.245336)
		(mid 338.074762 -268.195193)
		(end 337.887564 -268.245336)
		(width 0.088646)
		(layer "In6.Cu")
		(net "M_C_CPU0_SA_DQ<13>")
	)
	(arc
		(start 342.96096 -268.245336)
		(mid 342.773762 -268.195193)
		(end 342.586564 -268.245336)
		(width 0.088646)
		(layer "In6.Cu")
		(net "M_C_CPU0_SA_DQ<13>")
	)
	(arc
		(start 337.887564 -268.245336)
		(mid 337.604862 -268.321112)
		(end 337.32216 -268.245336)
		(width 0.088646)
		(layer "In6.Cu")
		(net "M_C_CPU0_SA_DQ<13>")
	)
	(arc
		(start 340.141814 -268.245336)
		(mid 339.954616 -268.195193)
		(end 339.767418 -268.245336)
		(width 0.088646)
		(layer "In6.Cu")
		(net "M_C_CPU0_SA_DQ<13>")
	)
	(segment
		(start 274.40001 -300.591728)
		(end 274.152106 -300.591728)
		(width 0.101854)
		(layer "F.Cu")
		(net "M_C_CPU0_SA_DQ<12>")
	)
	(segment
		(start 274.143978 -300.5836)
		(end 273.58213 -300.5836)
		(width 0.20066)
		(layer "F.Cu")
		(net "M_C_CPU0_SA_DQ<12>")
	)
	(segment
		(start 273.58213 -300.5836)
		(end 273.37258 -300.79315)
		(width 0.20066)
		(layer "F.Cu")
		(net "M_C_CPU0_SA_DQ<12>")
	)
	(segment
		(start 276.469094 -300.591728)
		(end 274.40001 -300.591728)
		(width 0.1016)
		(layer "F.Cu")
		(net "M_C_CPU0_SA_DQ<12>")
	)
	(segment
		(start 343.243662 -268.847824)
		(end 343.243662 -269.38351)
		(width 0.20066)
		(layer "F.Cu")
		(net "M_C_CPU0_SA_DQ<12>")
	)
	(segment
		(start 279.816814 -301.01667)
		(end 278.711914 -301.01667)
		(width 0.20066)
		(layer "F.Cu")
		(net "M_C_CPU0_SA_DQ<12>")
	)
	(segment
		(start 273.19986 -301.25543)
		(end 272.741136 -301.25543)
		(width 0.20066)
		(layer "F.Cu")
		(net "M_C_CPU0_SA_DQ<12>")
	)
	(segment
		(start 272.741136 -301.25543)
		(end 272.502376 -301.01667)
		(width 0.20066)
		(layer "F.Cu")
		(net "M_C_CPU0_SA_DQ<12>")
	)
	(segment
		(start 343.243916 -268.84757)
		(end 343.243662 -268.847824)
		(width 0.20066)
		(layer "F.Cu")
		(net "M_C_CPU0_SA_DQ<12>")
	)
	(segment
		(start 273.37258 -300.79315)
		(end 273.37258 -301.08271)
		(width 0.20066)
		(layer "F.Cu")
		(net "M_C_CPU0_SA_DQ<12>")
	)
	(segment
		(start 276.917912 -300.591728)
		(end 276.469094 -300.591728)
		(width 0.20066)
		(layer "F.Cu")
		(net "M_C_CPU0_SA_DQ<12>")
	)
	(segment
		(start 272.502376 -301.01667)
		(end 271.168114 -301.01667)
		(width 0.20066)
		(layer "F.Cu")
		(net "M_C_CPU0_SA_DQ<12>")
	)
	(segment
		(start 274.152106 -300.591728)
		(end 274.143978 -300.5836)
		(width 0.101854)
		(layer "F.Cu")
		(net "M_C_CPU0_SA_DQ<12>")
	)
	(segment
		(start 277.342854 -301.01667)
		(end 276.917912 -300.591728)
		(width 0.20066)
		(layer "F.Cu")
		(net "M_C_CPU0_SA_DQ<12>")
	)
	(segment
		(start 273.37258 -301.08271)
		(end 273.19986 -301.25543)
		(width 0.20066)
		(layer "F.Cu")
		(net "M_C_CPU0_SA_DQ<12>")
	)
	(segment
		(start 278.711914 -301.01667)
		(end 277.342854 -301.01667)
		(width 0.20066)
		(layer "F.Cu")
		(net "M_C_CPU0_SA_DQ<12>")
	)
	(segment
		(start 302.984662 -288.5694)
		(end 302.26762 -288.5694)
		(width 0.18288)
		(layer "In6.Cu")
		(net "M_C_CPU0_SA_DQ<12>")
	)
	(segment
		(start 303.902364 -287.651698)
		(end 302.984662 -288.5694)
		(width 0.18288)
		(layer "In6.Cu")
		(net "M_C_CPU0_SA_DQ<12>")
	)
	(segment
		(start 307.057552 -285.958026)
		(end 306.501546 -285.958026)
		(width 0.18288)
		(layer "In6.Cu")
		(net "M_C_CPU0_SA_DQ<12>")
	)
	(segment
		(start 331.98435 -271.39265)
		(end 331.98435 -271.97685)
		(width 0.088646)
		(layer "In6.Cu")
		(net "M_C_CPU0_SA_DQ<12>")
	)
	(segment
		(start 342.872568 -269.282672)
		(end 342.49106 -269.059152)
		(width 0.088646)
		(layer "In6.Cu")
		(net "M_C_CPU0_SA_DQ<12>")
	)
	(segment
		(start 304.807874 -287.651698)
		(end 303.902364 -287.651698)
		(width 0.18288)
		(layer "In6.Cu")
		(net "M_C_CPU0_SA_DQ<12>")
	)
	(segment
		(start 283.188156 -300.408848)
		(end 283.188156 -299.929042)
		(width 0.18288)
		(layer "In6.Cu")
		(net "M_C_CPU0_SA_DQ<12>")
	)
	(segment
		(start 332.758288 -270.618712)
		(end 331.98435 -271.39265)
		(width 0.088646)
		(layer "In6.Cu")
		(net "M_C_CPU0_SA_DQ<12>")
	)
	(segment
		(start 313.721242 -283.378656)
		(end 313.153044 -283.946854)
		(width 0.18288)
		(layer "In6.Cu")
		(net "M_C_CPU0_SA_DQ<12>")
	)
	(segment
		(start 340.237064 -269.059152)
		(end 340.22665 -269.065248)
		(width 0.088646)
		(layer "In6.Cu")
		(net "M_C_CPU0_SA_DQ<12>")
	)
	(segment
		(start 339.297518 -269.059152)
		(end 339.287104 -269.065248)
		(width 0.088646)
		(layer "In6.Cu")
		(net "M_C_CPU0_SA_DQ<12>")
	)
	(segment
		(start 281.806396 -300.408848)
		(end 281.806396 -299.929042)
		(width 0.18288)
		(layer "In6.Cu")
		(net "M_C_CPU0_SA_DQ<12>")
	)
	(segment
		(start 302.26762 -288.5694)
		(end 300.445424 -290.391596)
		(width 0.18288)
		(layer "In6.Cu")
		(net "M_C_CPU0_SA_DQ<12>")
	)
	(segment
		(start 281.806396 -299.929042)
		(end 281.623516 -299.746162)
		(width 0.18288)
		(layer "In6.Cu")
		(net "M_C_CPU0_SA_DQ<12>")
	)
	(segment
		(start 281.989276 -300.591728)
		(end 281.806396 -300.408848)
		(width 0.18288)
		(layer "In6.Cu")
		(net "M_C_CPU0_SA_DQ<12>")
	)
	(segment
		(start 300.445424 -290.391596)
		(end 297.836336 -290.391596)
		(width 0.18288)
		(layer "In6.Cu")
		(net "M_C_CPU0_SA_DQ<12>")
	)
	(segment
		(start 307.68671 -286.145732)
		(end 307.245258 -286.145732)
		(width 0.18288)
		(layer "In6.Cu")
		(net "M_C_CPU0_SA_DQ<12>")
	)
	(segment
		(start 307.890418 -286.061404)
		(end 307.68671 -286.145732)
		(width 0.18288)
		(layer "In6.Cu")
		(net "M_C_CPU0_SA_DQ<12>")
	)
	(segment
		(start 280.241756 -300.591728)
		(end 279.816814 -301.01667)
		(width 0.18288)
		(layer "In6.Cu")
		(net "M_C_CPU0_SA_DQ<12>")
	)
	(segment
		(start 334.410812 -269.38351)
		(end 334.410812 -269.402052)
		(width 0.088646)
		(layer "In6.Cu")
		(net "M_C_CPU0_SA_DQ<12>")
	)
	(segment
		(start 313.153044 -283.946854)
		(end 311.960768 -283.946854)
		(width 0.18288)
		(layer "In6.Cu")
		(net "M_C_CPU0_SA_DQ<12>")
	)
	(segment
		(start 282.314396 -300.591728)
		(end 281.989276 -300.591728)
		(width 0.18288)
		(layer "In6.Cu")
		(net "M_C_CPU0_SA_DQ<12>")
	)
	(segment
		(start 311.960768 -283.946854)
		(end 310.674258 -285.233364)
		(width 0.18288)
		(layer "In6.Cu")
		(net "M_C_CPU0_SA_DQ<12>")
	)
	(segment
		(start 333.010256 -270.618712)
		(end 332.758288 -270.618712)
		(width 0.088646)
		(layer "In6.Cu")
		(net "M_C_CPU0_SA_DQ<12>")
	)
	(segment
		(start 286.22244 -300.591728)
		(end 283.371036 -300.591728)
		(width 0.18288)
		(layer "In6.Cu")
		(net "M_C_CPU0_SA_DQ<12>")
	)
	(segment
		(start 323.08038 -275.579078)
		(end 315.280802 -283.378656)
		(width 0.18288)
		(layer "In6.Cu")
		(net "M_C_CPU0_SA_DQ<12>")
	)
	(segment
		(start 297.836336 -290.391596)
		(end 296.985944 -291.241988)
		(width 0.18288)
		(layer "In6.Cu")
		(net "M_C_CPU0_SA_DQ<12>")
	)
	(segment
		(start 282.680156 -299.746162)
		(end 282.497276 -299.929042)
		(width 0.18288)
		(layer "In6.Cu")
		(net "M_C_CPU0_SA_DQ<12>")
	)
	(segment
		(start 315.280802 -283.378656)
		(end 313.721242 -283.378656)
		(width 0.18288)
		(layer "In6.Cu")
		(net "M_C_CPU0_SA_DQ<12>")
	)
	(segment
		(start 282.497276 -300.408848)
		(end 282.314396 -300.591728)
		(width 0.18288)
		(layer "In6.Cu")
		(net "M_C_CPU0_SA_DQ<12>")
	)
	(segment
		(start 333.810864 -270.171926)
		(end 333.457042 -270.171926)
		(width 0.088646)
		(layer "In6.Cu")
		(net "M_C_CPU0_SA_DQ<12>")
	)
	(segment
		(start 283.188156 -299.929042)
		(end 283.005276 -299.746162)
		(width 0.18288)
		(layer "In6.Cu")
		(net "M_C_CPU0_SA_DQ<12>")
	)
	(segment
		(start 334.050386 -269.932404)
		(end 333.810864 -270.171926)
		(width 0.088646)
		(layer "In6.Cu")
		(net "M_C_CPU0_SA_DQ<12>")
	)
	(segment
		(start 309.063136 -285.95701)
		(end 307.994812 -285.95701)
		(width 0.18288)
		(layer "In6.Cu")
		(net "M_C_CPU0_SA_DQ<12>")
	)
	(segment
		(start 291.830506 -292.720014)
		(end 290.128198 -292.720014)
		(width 0.18288)
		(layer "In6.Cu")
		(net "M_C_CPU0_SA_DQ<12>")
	)
	(segment
		(start 334.598264 -269.059152)
		(end 334.589374 -269.064232)
		(width 0.088646)
		(layer "In6.Cu")
		(net "M_C_CPU0_SA_DQ<12>")
	)
	(segment
		(start 309.786782 -285.233364)
		(end 309.063136 -285.95701)
		(width 0.18288)
		(layer "In6.Cu")
		(net "M_C_CPU0_SA_DQ<12>")
	)
	(segment
		(start 341.176864 -269.059152)
		(end 341.162132 -269.067788)
		(width 0.088646)
		(layer "In6.Cu")
		(net "M_C_CPU0_SA_DQ<12>")
	)
	(segment
		(start 296.985944 -291.241988)
		(end 293.308532 -291.241988)
		(width 0.18288)
		(layer "In6.Cu")
		(net "M_C_CPU0_SA_DQ<12>")
	)
	(segment
		(start 293.308532 -291.241988)
		(end 291.830506 -292.720014)
		(width 0.18288)
		(layer "In6.Cu")
		(net "M_C_CPU0_SA_DQ<12>")
	)
	(segment
		(start 287.844484 -295.003728)
		(end 287.844484 -298.969684)
		(width 0.18288)
		(layer "In6.Cu")
		(net "M_C_CPU0_SA_DQ<12>")
	)
	(segment
		(start 281.115516 -300.408848)
		(end 280.932636 -300.591728)
		(width 0.18288)
		(layer "In6.Cu")
		(net "M_C_CPU0_SA_DQ<12>")
	)
	(segment
		(start 280.932636 -300.591728)
		(end 280.241756 -300.591728)
		(width 0.18288)
		(layer "In6.Cu")
		(net "M_C_CPU0_SA_DQ<12>")
	)
	(segment
		(start 330.510388 -272.50136)
		(end 323.08038 -275.579078)
		(width 0.18288)
		(layer "In6.Cu")
		(net "M_C_CPU0_SA_DQ<12>")
	)
	(segment
		(start 281.623516 -299.746162)
		(end 281.298396 -299.746162)
		(width 0.18288)
		(layer "In6.Cu")
		(net "M_C_CPU0_SA_DQ<12>")
	)
	(segment
		(start 331.283056 -272.50136)
		(end 330.510388 -272.50136)
		(width 0.18288)
		(layer "In6.Cu")
		(net "M_C_CPU0_SA_DQ<12>")
	)
	(segment
		(start 306.501546 -285.958026)
		(end 304.807874 -287.651698)
		(width 0.18288)
		(layer "In6.Cu")
		(net "M_C_CPU0_SA_DQ<12>")
	)
	(segment
		(start 331.45984 -272.50136)
		(end 331.283056 -272.50136)
		(width 0.088646)
		(layer "In6.Cu")
		(net "M_C_CPU0_SA_DQ<12>")
	)
	(segment
		(start 281.115516 -299.929042)
		(end 281.115516 -300.408848)
		(width 0.18288)
		(layer "In6.Cu")
		(net "M_C_CPU0_SA_DQ<12>")
	)
	(segment
		(start 307.994812 -285.95701)
		(end 307.890418 -286.061404)
		(width 0.18288)
		(layer "In6.Cu")
		(net "M_C_CPU0_SA_DQ<12>")
	)
	(segment
		(start 283.005276 -299.746162)
		(end 282.680156 -299.746162)
		(width 0.18288)
		(layer "In6.Cu")
		(net "M_C_CPU0_SA_DQ<12>")
	)
	(segment
		(start 333.457042 -270.171926)
		(end 333.010256 -270.618712)
		(width 0.088646)
		(layer "In6.Cu")
		(net "M_C_CPU0_SA_DQ<12>")
	)
	(segment
		(start 281.298396 -299.746162)
		(end 281.115516 -299.929042)
		(width 0.18288)
		(layer "In6.Cu")
		(net "M_C_CPU0_SA_DQ<12>")
	)
	(segment
		(start 287.844484 -298.969684)
		(end 286.22244 -300.591728)
		(width 0.18288)
		(layer "In6.Cu")
		(net "M_C_CPU0_SA_DQ<12>")
	)
	(segment
		(start 290.128198 -292.720014)
		(end 287.844484 -295.003728)
		(width 0.18288)
		(layer "In6.Cu")
		(net "M_C_CPU0_SA_DQ<12>")
	)
	(segment
		(start 307.245258 -286.145732)
		(end 307.057552 -285.958026)
		(width 0.18288)
		(layer "In6.Cu")
		(net "M_C_CPU0_SA_DQ<12>")
	)
	(segment
		(start 331.98435 -271.97685)
		(end 331.45984 -272.50136)
		(width 0.088646)
		(layer "In6.Cu")
		(net "M_C_CPU0_SA_DQ<12>")
	)
	(segment
		(start 282.497276 -299.929042)
		(end 282.497276 -300.408848)
		(width 0.18288)
		(layer "In6.Cu")
		(net "M_C_CPU0_SA_DQ<12>")
	)
	(segment
		(start 310.674258 -285.233364)
		(end 309.786782 -285.233364)
		(width 0.18288)
		(layer "In6.Cu")
		(net "M_C_CPU0_SA_DQ<12>")
	)
	(segment
		(start 283.371036 -300.591728)
		(end 283.188156 -300.408848)
		(width 0.18288)
		(layer "In6.Cu")
		(net "M_C_CPU0_SA_DQ<12>")
	)
	(segment
		(start 343.243662 -269.38351)
		(end 342.872568 -269.282672)
		(width 0.088646)
		(layer "In6.Cu")
		(net "M_C_CPU0_SA_DQ<12>")
	)
	(segment
		(start 342.116664 -269.059152)
		(end 342.101932 -269.067788)
		(width 0.088646)
		(layer "In6.Cu")
		(net "M_C_CPU0_SA_DQ<12>")
	)
	(arc
		(start 336.85226 -269.059152)
		(mid 336.665062 -269.009009)
		(end 336.477864 -269.059152)
		(width 0.088646)
		(layer "In6.Cu")
		(net "M_C_CPU0_SA_DQ<12>")
	)
	(arc
		(start 336.477864 -269.059152)
		(mid 336.195162 -269.134928)
		(end 335.91246 -269.059152)
		(width 0.088646)
		(layer "In6.Cu")
		(net "M_C_CPU0_SA_DQ<12>")
	)
	(arc
		(start 342.49106 -269.059152)
		(mid 342.303862 -269.009009)
		(end 342.116664 -269.059152)
		(width 0.088646)
		(layer "In6.Cu")
		(net "M_C_CPU0_SA_DQ<12>")
	)
	(arc
		(start 335.91246 -269.059152)
		(mid 335.725262 -269.009009)
		(end 335.538064 -269.059152)
		(width 0.088646)
		(layer "In6.Cu")
		(net "M_C_CPU0_SA_DQ<12>")
	)
	(arc
		(start 339.671914 -269.059152)
		(mid 339.484716 -269.009009)
		(end 339.297518 -269.059152)
		(width 0.088646)
		(layer "In6.Cu")
		(net "M_C_CPU0_SA_DQ<12>")
	)
	(arc
		(start 337.417664 -269.059152)
		(mid 337.134962 -269.134928)
		(end 336.85226 -269.059152)
		(width 0.088646)
		(layer "In6.Cu")
		(net "M_C_CPU0_SA_DQ<12>")
	)
	(arc
		(start 334.410812 -269.402052)
		(mid 334.33065 -269.674241)
		(end 334.128364 -269.873222)
		(width 0.088646)
		(layer "In6.Cu")
		(net "M_C_CPU0_SA_DQ<12>")
	)
	(arc
		(start 338.73186 -269.059152)
		(mid 338.544662 -269.009009)
		(end 338.357464 -269.059152)
		(width 0.088646)
		(layer "In6.Cu")
		(net "M_C_CPU0_SA_DQ<12>")
	)
	(arc
		(start 337.79206 -269.059152)
		(mid 337.604862 -269.009009)
		(end 337.417664 -269.059152)
		(width 0.088646)
		(layer "In6.Cu")
		(net "M_C_CPU0_SA_DQ<12>")
	)
	(arc
		(start 341.55126 -269.059152)
		(mid 341.364062 -269.009009)
		(end 341.176864 -269.059152)
		(width 0.088646)
		(layer "In6.Cu")
		(net "M_C_CPU0_SA_DQ<12>")
	)
	(arc
		(start 338.357464 -269.059152)
		(mid 338.074762 -269.134928)
		(end 337.79206 -269.059152)
		(width 0.088646)
		(layer "In6.Cu")
		(net "M_C_CPU0_SA_DQ<12>")
	)
	(arc
		(start 340.22665 -269.065248)
		(mid 339.948472 -269.134971)
		(end 339.671914 -269.059152)
		(width 0.088646)
		(layer "In6.Cu")
		(net "M_C_CPU0_SA_DQ<12>")
	)
	(arc
		(start 340.61146 -269.059152)
		(mid 340.424262 -269.009009)
		(end 340.237064 -269.059152)
		(width 0.088646)
		(layer "In6.Cu")
		(net "M_C_CPU0_SA_DQ<12>")
	)
	(arc
		(start 335.538064 -269.059152)
		(mid 335.255362 -269.134928)
		(end 334.97266 -269.059152)
		(width 0.088646)
		(layer "In6.Cu")
		(net "M_C_CPU0_SA_DQ<12>")
	)
	(arc
		(start 339.287104 -269.065248)
		(mid 339.008672 -269.135094)
		(end 338.73186 -269.059152)
		(width 0.088646)
		(layer "In6.Cu")
		(net "M_C_CPU0_SA_DQ<12>")
	)
	(arc
		(start 342.101932 -269.067788)
		(mid 341.825457 -269.135108)
		(end 341.55126 -269.059152)
		(width 0.088646)
		(layer "In6.Cu")
		(net "M_C_CPU0_SA_DQ<12>")
	)
	(arc
		(start 334.97266 -269.059152)
		(mid 334.785462 -269.009009)
		(end 334.598264 -269.059152)
		(width 0.088646)
		(layer "In6.Cu")
		(net "M_C_CPU0_SA_DQ<12>")
	)
	(arc
		(start 334.128364 -269.873222)
		(mid 334.087434 -269.900255)
		(end 334.050386 -269.932404)
		(width 0.088646)
		(layer "In6.Cu")
		(net "M_C_CPU0_SA_DQ<12>")
	)
	(arc
		(start 334.589374 -269.064232)
		(mid 334.45846 -269.200592)
		(end 334.410812 -269.38351)
		(width 0.088646)
		(layer "In6.Cu")
		(net "M_C_CPU0_SA_DQ<12>")
	)
	(arc
		(start 341.162132 -269.067788)
		(mid 340.885657 -269.135108)
		(end 340.61146 -269.059152)
		(width 0.088646)
		(layer "In6.Cu")
		(net "M_C_CPU0_SA_DQ<12>")
	)
	(segment
		(start 282.811982 -304.416714)
		(end 281.99588 -304.416714)
		(width 0.20066)
		(layer "F.Cu")
		(net "M_C_CPU0_SA_DQ<11>")
	)
	(segment
		(start 283.916882 -304.416714)
		(end 282.811982 -304.416714)
		(width 0.20066)
		(layer "F.Cu")
		(net "M_C_CPU0_SA_DQ<11>")
	)
	(segment
		(start 281.788362 -304.624232)
		(end 281.34183 -304.624232)
		(width 0.20066)
		(layer "F.Cu")
		(net "M_C_CPU0_SA_DQ<11>")
	)
	(segment
		(start 277.091394 -304.542698)
		(end 276.96541 -304.416714)
		(width 0.20066)
		(layer "F.Cu")
		(net "M_C_CPU0_SA_DQ<11>")
	)
	(segment
		(start 280.606246 -304.54092)
		(end 280.606246 -304.692558)
		(width 0.20066)
		(layer "F.Cu")
		(net "M_C_CPU0_SA_DQ<11>")
	)
	(segment
		(start 277.233888 -304.85588)
		(end 277.091394 -304.713386)
		(width 0.20066)
		(layer "F.Cu")
		(net "M_C_CPU0_SA_DQ<11>")
	)
	(segment
		(start 281.34183 -304.624232)
		(end 281.129994 -304.412396)
		(width 0.20066)
		(layer "F.Cu")
		(net "M_C_CPU0_SA_DQ<11>")
	)
	(segment
		(start 277.839932 -304.841656)
		(end 277.601934 -304.841656)
		(width 0.101854)
		(layer "F.Cu")
		(net "M_C_CPU0_SA_DQ<11>")
	)
	(segment
		(start 277.58771 -304.85588)
		(end 277.233888 -304.85588)
		(width 0.20066)
		(layer "F.Cu")
		(net "M_C_CPU0_SA_DQ<11>")
	)
	(segment
		(start 276.96541 -304.416714)
		(end 275.268182 -304.416714)
		(width 0.20066)
		(layer "F.Cu")
		(net "M_C_CPU0_SA_DQ<11>")
	)
	(segment
		(start 281.129994 -304.412396)
		(end 280.73477 -304.412396)
		(width 0.20066)
		(layer "F.Cu")
		(net "M_C_CPU0_SA_DQ<11>")
	)
	(segment
		(start 280.73477 -304.412396)
		(end 280.606246 -304.54092)
		(width 0.20066)
		(layer "F.Cu")
		(net "M_C_CPU0_SA_DQ<11>")
	)
	(segment
		(start 281.99588 -304.416714)
		(end 281.788362 -304.624232)
		(width 0.20066)
		(layer "F.Cu")
		(net "M_C_CPU0_SA_DQ<11>")
	)
	(segment
		(start 280.457148 -304.841656)
		(end 279.912826 -304.841656)
		(width 0.20066)
		(layer "F.Cu")
		(net "M_C_CPU0_SA_DQ<11>")
	)
	(segment
		(start 277.601934 -304.841656)
		(end 277.58771 -304.85588)
		(width 0.101854)
		(layer "F.Cu")
		(net "M_C_CPU0_SA_DQ<11>")
	)
	(segment
		(start 277.091394 -304.713386)
		(end 277.091394 -304.542698)
		(width 0.20066)
		(layer "F.Cu")
		(net "M_C_CPU0_SA_DQ<11>")
	)
	(segment
		(start 280.606246 -304.692558)
		(end 280.457148 -304.841656)
		(width 0.20066)
		(layer "F.Cu")
		(net "M_C_CPU0_SA_DQ<11>")
	)
	(segment
		(start 279.912826 -304.841656)
		(end 277.839932 -304.841656)
		(width 0.1016)
		(layer "F.Cu")
		(net "M_C_CPU0_SA_DQ<11>")
	)
	(arc
		(start 345.123516 -270.475456)
		(mid 345.123452 -270.743426)
		(end 345.123262 -271.011396)
		(width 0.20066)
		(layer "F.Cu")
		(net "M_C_CPU0_SA_DQ<11>")
	)
	(segment
		(start 308.326028 -289.84702)
		(end 307.579268 -289.84702)
		(width 0.18288)
		(layer "In6.Cu")
		(net "M_C_CPU0_SA_DQ<11>")
	)
	(segment
		(start 342.116918 -271.335754)
		(end 342.106504 -271.329658)
		(width 0.088646)
		(layer "In6.Cu")
		(net "M_C_CPU0_SA_DQ<11>")
	)
	(segment
		(start 334.04175 -272.95856)
		(end 334.03286 -272.96364)
		(width 0.088646)
		(layer "In6.Cu")
		(net "M_C_CPU0_SA_DQ<11>")
	)
	(segment
		(start 313.647074 -287.418526)
		(end 311.21858 -289.84702)
		(width 0.18288)
		(layer "In6.Cu")
		(net "M_C_CPU0_SA_DQ<11>")
	)
	(segment
		(start 295.676066 -296.3418)
		(end 293.956486 -296.3418)
		(width 0.18288)
		(layer "In6.Cu")
		(net "M_C_CPU0_SA_DQ<11>")
	)
	(segment
		(start 292.323774 -296.00271)
		(end 290.991544 -297.33494)
		(width 0.18288)
		(layer "In6.Cu")
		(net "M_C_CPU0_SA_DQ<11>")
	)
	(segment
		(start 331.84211 -274.719034)
		(end 331.283056 -274.719034)
		(width 0.088646)
		(layer "In6.Cu")
		(net "M_C_CPU0_SA_DQ<11>")
	)
	(segment
		(start 301.861474 -293.766748)
		(end 301.861474 -294.025066)
		(width 0.18288)
		(layer "In6.Cu")
		(net "M_C_CPU0_SA_DQ<11>")
	)
	(segment
		(start 301.161958 -294.044624)
		(end 300.903386 -294.044624)
		(width 0.18288)
		(layer "In6.Cu")
		(net "M_C_CPU0_SA_DQ<11>")
	)
	(segment
		(start 335.630012 -271.815306)
		(end 335.630012 -271.825212)
		(width 0.088646)
		(layer "In6.Cu")
		(net "M_C_CPU0_SA_DQ<11>")
	)
	(segment
		(start 300.394624 -295.491916)
		(end 296.52595 -295.491916)
		(width 0.18288)
		(layer "In6.Cu")
		(net "M_C_CPU0_SA_DQ<11>")
	)
	(segment
		(start 331.283056 -274.719034)
		(end 330.73086 -274.719034)
		(width 0.18288)
		(layer "In6.Cu")
		(net "M_C_CPU0_SA_DQ<11>")
	)
	(segment
		(start 285.319216 -304.884582)
		(end 284.38475 -304.884582)
		(width 0.18288)
		(layer "In6.Cu")
		(net "M_C_CPU0_SA_DQ<11>")
	)
	(segment
		(start 308.508908 -289.66414)
		(end 308.326028 -289.84702)
		(width 0.18288)
		(layer "In6.Cu")
		(net "M_C_CPU0_SA_DQ<11>")
	)
	(segment
		(start 290.991544 -301.256446)
		(end 290.032694 -302.215296)
		(width 0.18288)
		(layer "In6.Cu")
		(net "M_C_CPU0_SA_DQ<11>")
	)
	(segment
		(start 302.13935 -293.067232)
		(end 301.880778 -293.067232)
		(width 0.18288)
		(layer "In6.Cu")
		(net "M_C_CPU0_SA_DQ<11>")
	)
	(segment
		(start 332.97622 -273.053302)
		(end 332.90764 -273.21891)
		(width 0.088646)
		(layer "In6.Cu")
		(net "M_C_CPU0_SA_DQ<11>")
	)
	(segment
		(start 302.608742 -293.277798)
		(end 302.35017 -293.277798)
		(width 0.18288)
		(layer "In6.Cu")
		(net "M_C_CPU0_SA_DQ<11>")
	)
	(segment
		(start 340.237064 -271.335754)
		(end 340.222332 -271.327118)
		(width 0.088646)
		(layer "In6.Cu")
		(net "M_C_CPU0_SA_DQ<11>")
	)
	(segment
		(start 325.954644 -276.69744)
		(end 315.233558 -287.418526)
		(width 0.18288)
		(layer "In6.Cu")
		(net "M_C_CPU0_SA_DQ<11>")
	)
	(segment
		(start 308.691788 -289.058604)
		(end 308.508908 -289.241484)
		(width 0.18288)
		(layer "In6.Cu")
		(net "M_C_CPU0_SA_DQ<11>")
	)
	(segment
		(start 300.884082 -294.74414)
		(end 300.884082 -295.002458)
		(width 0.18288)
		(layer "In6.Cu")
		(net "M_C_CPU0_SA_DQ<11>")
	)
	(segment
		(start 311.21858 -289.84702)
		(end 309.382668 -289.84702)
		(width 0.18288)
		(layer "In6.Cu")
		(net "M_C_CPU0_SA_DQ<11>")
	)
	(segment
		(start 301.650654 -293.555928)
		(end 301.861474 -293.766748)
		(width 0.18288)
		(layer "In6.Cu")
		(net "M_C_CPU0_SA_DQ<11>")
	)
	(segment
		(start 335.068164 -272.14957)
		(end 335.053432 -272.140934)
		(width 0.088646)
		(layer "In6.Cu")
		(net "M_C_CPU0_SA_DQ<11>")
	)
	(segment
		(start 293.956486 -296.3418)
		(end 293.617396 -296.00271)
		(width 0.18288)
		(layer "In6.Cu")
		(net "M_C_CPU0_SA_DQ<11>")
	)
	(segment
		(start 304.169064 -292.500812)
		(end 303.385728 -292.500812)
		(width 0.18288)
		(layer "In6.Cu")
		(net "M_C_CPU0_SA_DQ<11>")
	)
	(segment
		(start 293.617396 -296.00271)
		(end 292.323774 -296.00271)
		(width 0.18288)
		(layer "In6.Cu")
		(net "M_C_CPU0_SA_DQ<11>")
	)
	(segment
		(start 306.897532 -290.528756)
		(end 306.14112 -290.528756)
		(width 0.18288)
		(layer "In6.Cu")
		(net "M_C_CPU0_SA_DQ<11>")
	)
	(segment
		(start 337.417664 -271.335754)
		(end 337.402932 -271.327118)
		(width 0.088646)
		(layer "In6.Cu")
		(net "M_C_CPU0_SA_DQ<11>")
	)
	(segment
		(start 344.788998 -270.923512)
		(end 344.365072 -270.683736)
		(width 0.088646)
		(layer "In6.Cu")
		(net "M_C_CPU0_SA_DQ<11>")
	)
	(segment
		(start 307.579268 -289.84702)
		(end 306.897532 -290.528756)
		(width 0.18288)
		(layer "In6.Cu")
		(net "M_C_CPU0_SA_DQ<11>")
	)
	(segment
		(start 342.702642 -271.166082)
		(end 342.670892 -271.198086)
		(width 0.088646)
		(layer "In6.Cu")
		(net "M_C_CPU0_SA_DQ<11>")
	)
	(segment
		(start 300.673262 -294.274748)
		(end 300.673262 -294.53332)
		(width 0.18288)
		(layer "In6.Cu")
		(net "M_C_CPU0_SA_DQ<11>")
	)
	(segment
		(start 301.861474 -294.025066)
		(end 301.63135 -294.25519)
		(width 0.18288)
		(layer "In6.Cu")
		(net "M_C_CPU0_SA_DQ<11>")
	)
	(segment
		(start 333.658464 -272.96364)
		(end 333.64805 -272.957544)
		(width 0.088646)
		(layer "In6.Cu")
		(net "M_C_CPU0_SA_DQ<11>")
	)
	(segment
		(start 342.491822 -271.3355)
		(end 342.491314 -271.335754)
		(width 0.088646)
		(layer "In6.Cu")
		(net "M_C_CPU0_SA_DQ<11>")
	)
	(segment
		(start 341.176864 -271.335754)
		(end 341.162132 -271.327118)
		(width 0.088646)
		(layer "In6.Cu")
		(net "M_C_CPU0_SA_DQ<11>")
	)
	(segment
		(start 302.35017 -293.277798)
		(end 302.13935 -293.067232)
		(width 0.18288)
		(layer "In6.Cu")
		(net "M_C_CPU0_SA_DQ<11>")
	)
	(segment
		(start 301.372778 -294.25519)
		(end 301.161958 -294.044624)
		(width 0.18288)
		(layer "In6.Cu")
		(net "M_C_CPU0_SA_DQ<11>")
	)
	(segment
		(start 290.032694 -302.215296)
		(end 286.542988 -303.66081)
		(width 0.18288)
		(layer "In6.Cu")
		(net "M_C_CPU0_SA_DQ<11>")
	)
	(segment
		(start 309.199788 -289.241484)
		(end 309.016908 -289.058604)
		(width 0.18288)
		(layer "In6.Cu")
		(net "M_C_CPU0_SA_DQ<11>")
	)
	(segment
		(start 309.382668 -289.84702)
		(end 309.199788 -289.66414)
		(width 0.18288)
		(layer "In6.Cu")
		(net "M_C_CPU0_SA_DQ<11>")
	)
	(segment
		(start 300.903386 -294.044624)
		(end 300.673262 -294.274748)
		(width 0.18288)
		(layer "In6.Cu")
		(net "M_C_CPU0_SA_DQ<11>")
	)
	(segment
		(start 301.63135 -294.25519)
		(end 301.372778 -294.25519)
		(width 0.18288)
		(layer "In6.Cu")
		(net "M_C_CPU0_SA_DQ<11>")
	)
	(segment
		(start 286.542988 -303.66081)
		(end 285.319216 -304.884582)
		(width 0.18288)
		(layer "In6.Cu")
		(net "M_C_CPU0_SA_DQ<11>")
	)
	(segment
		(start 330.73086 -274.719034)
		(end 325.954644 -276.69744)
		(width 0.18288)
		(layer "In6.Cu")
		(net "M_C_CPU0_SA_DQ<11>")
	)
	(segment
		(start 335.45145 -272.14449)
		(end 335.44256 -272.14957)
		(width 0.088646)
		(layer "In6.Cu")
		(net "M_C_CPU0_SA_DQ<11>")
	)
	(segment
		(start 309.016908 -289.058604)
		(end 308.691788 -289.058604)
		(width 0.18288)
		(layer "In6.Cu")
		(net "M_C_CPU0_SA_DQ<11>")
	)
	(segment
		(start 301.650654 -293.297356)
		(end 301.650654 -293.555928)
		(width 0.18288)
		(layer "In6.Cu")
		(net "M_C_CPU0_SA_DQ<11>")
	)
	(segment
		(start 308.508908 -289.241484)
		(end 308.508908 -289.66414)
		(width 0.18288)
		(layer "In6.Cu")
		(net "M_C_CPU0_SA_DQ<11>")
	)
	(segment
		(start 315.233558 -287.418526)
		(end 313.647074 -287.418526)
		(width 0.18288)
		(layer "In6.Cu")
		(net "M_C_CPU0_SA_DQ<11>")
	)
	(segment
		(start 332.90764 -273.653504)
		(end 331.84211 -274.719034)
		(width 0.088646)
		(layer "In6.Cu")
		(net "M_C_CPU0_SA_DQ<11>")
	)
	(segment
		(start 296.52595 -295.491916)
		(end 295.676066 -296.3418)
		(width 0.18288)
		(layer "In6.Cu")
		(net "M_C_CPU0_SA_DQ<11>")
	)
	(segment
		(start 300.884082 -295.002458)
		(end 300.394624 -295.491916)
		(width 0.18288)
		(layer "In6.Cu")
		(net "M_C_CPU0_SA_DQ<11>")
	)
	(segment
		(start 303.385728 -292.500812)
		(end 302.608742 -293.277798)
		(width 0.18288)
		(layer "In6.Cu")
		(net "M_C_CPU0_SA_DQ<11>")
	)
	(segment
		(start 301.880778 -293.067232)
		(end 301.650654 -293.297356)
		(width 0.18288)
		(layer "In6.Cu")
		(net "M_C_CPU0_SA_DQ<11>")
	)
	(segment
		(start 284.38475 -304.884582)
		(end 283.916882 -304.416714)
		(width 0.18288)
		(layer "In6.Cu")
		(net "M_C_CPU0_SA_DQ<11>")
	)
	(segment
		(start 290.991544 -297.33494)
		(end 290.991544 -301.256446)
		(width 0.18288)
		(layer "In6.Cu")
		(net "M_C_CPU0_SA_DQ<11>")
	)
	(segment
		(start 343.436956 -270.69034)
		(end 343.425272 -270.683736)
		(width 0.088646)
		(layer "In6.Cu")
		(net "M_C_CPU0_SA_DQ<11>")
	)
	(segment
		(start 309.199788 -289.66414)
		(end 309.199788 -289.241484)
		(width 0.18288)
		(layer "In6.Cu")
		(net "M_C_CPU0_SA_DQ<11>")
	)
	(segment
		(start 342.796622 -270.939006)
		(end 342.768174 -271.00784)
		(width 0.088646)
		(layer "In6.Cu")
		(net "M_C_CPU0_SA_DQ<11>")
	)
	(segment
		(start 306.14112 -290.528756)
		(end 304.169064 -292.500812)
		(width 0.18288)
		(layer "In6.Cu")
		(net "M_C_CPU0_SA_DQ<11>")
	)
	(segment
		(start 334.220312 -272.625058)
		(end 334.220312 -272.639282)
		(width 0.088646)
		(layer "In6.Cu")
		(net "M_C_CPU0_SA_DQ<11>")
	)
	(segment
		(start 300.673262 -294.53332)
		(end 300.884082 -294.74414)
		(width 0.18288)
		(layer "In6.Cu")
		(net "M_C_CPU0_SA_DQ<11>")
	)
	(segment
		(start 332.90764 -273.21891)
		(end 332.90764 -273.653504)
		(width 0.088646)
		(layer "In6.Cu")
		(net "M_C_CPU0_SA_DQ<11>")
	)
	(arc
		(start 342.768174 -271.00784)
		(mid 342.75114 -271.093475)
		(end 342.702642 -271.166082)
		(width 0.088646)
		(layer "In6.Cu")
		(net "M_C_CPU0_SA_DQ<11>")
	)
	(arc
		(start 340.61146 -271.335754)
		(mid 340.424262 -271.385897)
		(end 340.237064 -271.335754)
		(width 0.088646)
		(layer "In6.Cu")
		(net "M_C_CPU0_SA_DQ<11>")
	)
	(arc
		(start 343.425272 -270.683736)
		(mid 343.240417 -270.636786)
		(end 343.056464 -270.687038)
		(width 0.088646)
		(layer "In6.Cu")
		(net "M_C_CPU0_SA_DQ<11>")
	)
	(arc
		(start 345.123262 -271.011396)
		(mid 344.950449 -270.989076)
		(end 344.788998 -270.923512)
		(width 0.088646)
		(layer "In6.Cu")
		(net "M_C_CPU0_SA_DQ<11>")
	)
	(arc
		(start 338.73186 -271.335754)
		(mid 338.544662 -271.385897)
		(end 338.357464 -271.335754)
		(width 0.088646)
		(layer "In6.Cu")
		(net "M_C_CPU0_SA_DQ<11>")
	)
	(arc
		(start 335.630012 -271.825212)
		(mid 335.582333 -272.008112)
		(end 335.45145 -272.14449)
		(width 0.088646)
		(layer "In6.Cu")
		(net "M_C_CPU0_SA_DQ<11>")
	)
	(arc
		(start 335.44256 -272.14957)
		(mid 335.255362 -272.199713)
		(end 335.068164 -272.14957)
		(width 0.088646)
		(layer "In6.Cu")
		(net "M_C_CPU0_SA_DQ<11>")
	)
	(arc
		(start 334.220312 -272.639282)
		(mid 334.172633 -272.822182)
		(end 334.04175 -272.95856)
		(width 0.088646)
		(layer "In6.Cu")
		(net "M_C_CPU0_SA_DQ<11>")
	)
	(arc
		(start 342.670892 -271.198086)
		(mid 342.585855 -271.272653)
		(end 342.491822 -271.3355)
		(width 0.088646)
		(layer "In6.Cu")
		(net "M_C_CPU0_SA_DQ<11>")
	)
	(arc
		(start 343.056464 -270.687038)
		(mid 342.958038 -270.75279)
		(end 342.869012 -270.830802)
		(width 0.088646)
		(layer "In6.Cu")
		(net "M_C_CPU0_SA_DQ<11>")
	)
	(arc
		(start 334.50276 -272.14957)
		(mid 334.299455 -272.350436)
		(end 334.220312 -272.625058)
		(width 0.088646)
		(layer "In6.Cu")
		(net "M_C_CPU0_SA_DQ<11>")
	)
	(arc
		(start 339.67166 -271.335754)
		(mid 339.484462 -271.385897)
		(end 339.297264 -271.335754)
		(width 0.088646)
		(layer "In6.Cu")
		(net "M_C_CPU0_SA_DQ<11>")
	)
	(arc
		(start 342.491314 -271.335754)
		(mid 342.304116 -271.385897)
		(end 342.116918 -271.335754)
		(width 0.088646)
		(layer "In6.Cu")
		(net "M_C_CPU0_SA_DQ<11>")
	)
	(arc
		(start 342.869012 -270.830802)
		(mid 342.827487 -270.881339)
		(end 342.796622 -270.939006)
		(width 0.088646)
		(layer "In6.Cu")
		(net "M_C_CPU0_SA_DQ<11>")
	)
	(arc
		(start 336.85226 -271.335754)
		(mid 336.665062 -271.385897)
		(end 336.477864 -271.335754)
		(width 0.088646)
		(layer "In6.Cu")
		(net "M_C_CPU0_SA_DQ<11>")
	)
	(arc
		(start 341.162132 -271.327118)
		(mid 340.885657 -271.259798)
		(end 340.61146 -271.335754)
		(width 0.088646)
		(layer "In6.Cu")
		(net "M_C_CPU0_SA_DQ<11>")
	)
	(arc
		(start 338.357464 -271.335754)
		(mid 338.074762 -271.259978)
		(end 337.79206 -271.335754)
		(width 0.088646)
		(layer "In6.Cu")
		(net "M_C_CPU0_SA_DQ<11>")
	)
	(arc
		(start 339.297264 -271.335754)
		(mid 339.014562 -271.259978)
		(end 338.73186 -271.335754)
		(width 0.088646)
		(layer "In6.Cu")
		(net "M_C_CPU0_SA_DQ<11>")
	)
	(arc
		(start 336.477864 -271.335754)
		(mid 336.195162 -271.259978)
		(end 335.91246 -271.335754)
		(width 0.088646)
		(layer "In6.Cu")
		(net "M_C_CPU0_SA_DQ<11>")
	)
	(arc
		(start 343.996264 -270.687038)
		(mid 343.717061 -270.762678)
		(end 343.436956 -270.69034)
		(width 0.088646)
		(layer "In6.Cu")
		(net "M_C_CPU0_SA_DQ<11>")
	)
	(arc
		(start 335.053432 -272.140934)
		(mid 334.776991 -272.073768)
		(end 334.50276 -272.14957)
		(width 0.088646)
		(layer "In6.Cu")
		(net "M_C_CPU0_SA_DQ<11>")
	)
	(arc
		(start 341.55126 -271.335754)
		(mid 341.364062 -271.385897)
		(end 341.176864 -271.335754)
		(width 0.088646)
		(layer "In6.Cu")
		(net "M_C_CPU0_SA_DQ<11>")
	)
	(arc
		(start 335.91246 -271.335754)
		(mid 335.708125 -271.538359)
		(end 335.630012 -271.815306)
		(width 0.088646)
		(layer "In6.Cu")
		(net "M_C_CPU0_SA_DQ<11>")
	)
	(arc
		(start 340.222332 -271.327118)
		(mid 339.945857 -271.259798)
		(end 339.67166 -271.335754)
		(width 0.088646)
		(layer "In6.Cu")
		(net "M_C_CPU0_SA_DQ<11>")
	)
	(arc
		(start 344.365072 -270.683736)
		(mid 344.180217 -270.636786)
		(end 343.996264 -270.687038)
		(width 0.088646)
		(layer "In6.Cu")
		(net "M_C_CPU0_SA_DQ<11>")
	)
	(arc
		(start 334.03286 -272.96364)
		(mid 333.845662 -273.013783)
		(end 333.658464 -272.96364)
		(width 0.088646)
		(layer "In6.Cu")
		(net "M_C_CPU0_SA_DQ<11>")
	)
	(arc
		(start 337.79206 -271.335754)
		(mid 337.604862 -271.385897)
		(end 337.417664 -271.335754)
		(width 0.088646)
		(layer "In6.Cu")
		(net "M_C_CPU0_SA_DQ<11>")
	)
	(arc
		(start 333.093314 -272.96364)
		(mid 333.031836 -273.004642)
		(end 332.97622 -273.053302)
		(width 0.088646)
		(layer "In6.Cu")
		(net "M_C_CPU0_SA_DQ<11>")
	)
	(arc
		(start 337.402932 -271.327118)
		(mid 337.126457 -271.259798)
		(end 336.85226 -271.335754)
		(width 0.088646)
		(layer "In6.Cu")
		(net "M_C_CPU0_SA_DQ<11>")
	)
	(arc
		(start 342.106504 -271.329658)
		(mid 341.828072 -271.259812)
		(end 341.55126 -271.335754)
		(width 0.088646)
		(layer "In6.Cu")
		(net "M_C_CPU0_SA_DQ<11>")
	)
	(arc
		(start 333.64805 -272.957544)
		(mid 333.369872 -272.887821)
		(end 333.093314 -272.96364)
		(width 0.088646)
		(layer "In6.Cu")
		(net "M_C_CPU0_SA_DQ<11>")
	)
	(segment
		(start 280.689558 -305.835558)
		(end 280.545794 -305.691794)
		(width 0.20066)
		(layer "F.Cu")
		(net "M_C_CPU0_SA_DQ<10>")
	)
	(segment
		(start 344.653362 -271.824958)
		(end 344.653616 -271.825212)
		(width 0.20066)
		(layer "F.Cu")
		(net "M_C_CPU0_SA_DQ<10>")
	)
	(segment
		(start 283.916882 -306.116736)
		(end 282.811982 -306.116736)
		(width 0.20066)
		(layer "F.Cu")
		(net "M_C_CPU0_SA_DQ<10>")
	)
	(segment
		(start 281.497278 -306.116736)
		(end 281.285442 -306.328572)
		(width 0.20066)
		(layer "F.Cu")
		(net "M_C_CPU0_SA_DQ<10>")
	)
	(segment
		(start 280.689558 -306.161186)
		(end 280.689558 -305.835558)
		(width 0.20066)
		(layer "F.Cu")
		(net "M_C_CPU0_SA_DQ<10>")
	)
	(segment
		(start 276.850348 -305.681634)
		(end 276.415246 -306.116736)
		(width 0.20066)
		(layer "F.Cu")
		(net "M_C_CPU0_SA_DQ<10>")
	)
	(segment
		(start 277.59787 -305.691794)
		(end 277.58771 -305.681634)
		(width 0.101854)
		(layer "F.Cu")
		(net "M_C_CPU0_SA_DQ<10>")
	)
	(segment
		(start 276.415246 -306.116736)
		(end 275.268182 -306.116736)
		(width 0.20066)
		(layer "F.Cu")
		(net "M_C_CPU0_SA_DQ<10>")
	)
	(segment
		(start 277.852886 -305.691794)
		(end 277.59787 -305.691794)
		(width 0.101854)
		(layer "F.Cu")
		(net "M_C_CPU0_SA_DQ<10>")
	)
	(segment
		(start 277.58771 -305.681634)
		(end 276.850348 -305.681634)
		(width 0.20066)
		(layer "F.Cu")
		(net "M_C_CPU0_SA_DQ<10>")
	)
	(segment
		(start 279.912826 -305.691794)
		(end 277.852886 -305.691794)
		(width 0.1016)
		(layer "F.Cu")
		(net "M_C_CPU0_SA_DQ<10>")
	)
	(segment
		(start 280.856944 -306.328572)
		(end 280.689558 -306.161186)
		(width 0.20066)
		(layer "F.Cu")
		(net "M_C_CPU0_SA_DQ<10>")
	)
	(segment
		(start 280.545794 -305.691794)
		(end 279.912826 -305.691794)
		(width 0.20066)
		(layer "F.Cu")
		(net "M_C_CPU0_SA_DQ<10>")
	)
	(segment
		(start 344.653362 -271.289272)
		(end 344.653362 -271.824958)
		(width 0.20066)
		(layer "F.Cu")
		(net "M_C_CPU0_SA_DQ<10>")
	)
	(segment
		(start 282.811982 -306.116736)
		(end 281.497278 -306.116736)
		(width 0.20066)
		(layer "F.Cu")
		(net "M_C_CPU0_SA_DQ<10>")
	)
	(segment
		(start 281.285442 -306.328572)
		(end 280.856944 -306.328572)
		(width 0.20066)
		(layer "F.Cu")
		(net "M_C_CPU0_SA_DQ<10>")
	)
	(segment
		(start 340.156546 -272.140934)
		(end 340.141814 -272.14957)
		(width 0.088646)
		(layer "In6.Cu")
		(net "M_C_CPU0_SA_DQ<10>")
	)
	(segment
		(start 308.288944 -291.798756)
		(end 307.995828 -292.091872)
		(width 0.18288)
		(layer "In6.Cu")
		(net "M_C_CPU0_SA_DQ<10>")
	)
	(segment
		(start 333.283814 -273.97329)
		(end 333.226918 -274.030186)
		(width 0.088646)
		(layer "In6.Cu")
		(net "M_C_CPU0_SA_DQ<10>")
	)
	(segment
		(start 301.38878 -296.085768)
		(end 301.38878 -296.34434)
		(width 0.18288)
		(layer "In6.Cu")
		(net "M_C_CPU0_SA_DQ<10>")
	)
	(segment
		(start 301.618904 -295.855644)
		(end 301.38878 -296.085768)
		(width 0.18288)
		(layer "In6.Cu")
		(net "M_C_CPU0_SA_DQ<10>")
	)
	(segment
		(start 334.690212 -273.453098)
		(end 334.690212 -273.461734)
		(width 0.088646)
		(layer "In6.Cu")
		(net "M_C_CPU0_SA_DQ<10>")
	)
	(segment
		(start 310.79948 -291.037518)
		(end 309.720488 -292.11651)
		(width 0.18288)
		(layer "In6.Cu")
		(net "M_C_CPU0_SA_DQ<10>")
	)
	(segment
		(start 287.02254 -304.903124)
		(end 285.358078 -306.567586)
		(width 0.18288)
		(layer "In6.Cu")
		(net "M_C_CPU0_SA_DQ<10>")
	)
	(segment
		(start 296.199814 -298.022518)
		(end 296.016934 -297.839638)
		(width 0.18288)
		(layer "In6.Cu")
		(net "M_C_CPU0_SA_DQ<10>")
	)
	(segment
		(start 303.958244 -293.691564)
		(end 303.214024 -294.435784)
		(width 0.18288)
		(layer "In6.Cu")
		(net "M_C_CPU0_SA_DQ<10>")
	)
	(segment
		(start 315.146436 -289.27298)
		(end 314.02274 -289.27298)
		(width 0.18288)
		(layer "In6.Cu")
		(net "M_C_CPU0_SA_DQ<10>")
	)
	(segment
		(start 293.16807 -299.750988)
		(end 293.16807 -302.075342)
		(width 0.18288)
		(layer "In6.Cu")
		(net "M_C_CPU0_SA_DQ<10>")
	)
	(segment
		(start 295.508934 -298.022518)
		(end 295.508934 -298.708826)
		(width 0.18288)
		(layer "In6.Cu")
		(net "M_C_CPU0_SA_DQ<10>")
	)
	(segment
		(start 306.059586 -292.727634)
		(end 306.262532 -292.93058)
		(width 0.18288)
		(layer "In6.Cu")
		(net "M_C_CPU0_SA_DQ<10>")
	)
	(segment
		(start 331.283056 -275.731732)
		(end 330.9493 -275.731732)
		(width 0.18288)
		(layer "In6.Cu")
		(net "M_C_CPU0_SA_DQ<10>")
	)
	(segment
		(start 306.469288 -292.091872)
		(end 306.059586 -292.501574)
		(width 0.18288)
		(layer "In6.Cu")
		(net "M_C_CPU0_SA_DQ<10>")
	)
	(segment
		(start 307.995828 -292.091872)
		(end 306.469288 -292.091872)
		(width 0.18288)
		(layer "In6.Cu")
		(net "M_C_CPU0_SA_DQ<10>")
	)
	(segment
		(start 306.059586 -292.501574)
		(end 306.059586 -292.727634)
		(width 0.18288)
		(layer "In6.Cu")
		(net "M_C_CPU0_SA_DQ<10>")
	)
	(segment
		(start 309.258208 -292.11651)
		(end 308.940454 -291.798756)
		(width 0.18288)
		(layer "In6.Cu")
		(net "M_C_CPU0_SA_DQ<10>")
	)
	(segment
		(start 305.772058 -293.421054)
		(end 305.569112 -293.218108)
		(width 0.18288)
		(layer "In6.Cu")
		(net "M_C_CPU0_SA_DQ<10>")
	)
	(segment
		(start 291.34562 -302.978312)
		(end 290.139882 -304.18405)
		(width 0.18288)
		(layer "In6.Cu")
		(net "M_C_CPU0_SA_DQ<10>")
	)
	(segment
		(start 333.577946 -273.76882)
		(end 333.563214 -273.777456)
		(width 0.088646)
		(layer "In6.Cu")
		(net "M_C_CPU0_SA_DQ<10>")
	)
	(segment
		(start 287.87852 -304.903124)
		(end 287.02254 -304.903124)
		(width 0.18288)
		(layer "In6.Cu")
		(net "M_C_CPU0_SA_DQ<10>")
	)
	(segment
		(start 338.827364 -272.14957)
		(end 338.812632 -272.140934)
		(width 0.088646)
		(layer "In6.Cu")
		(net "M_C_CPU0_SA_DQ<10>")
	)
	(segment
		(start 306.262532 -293.15664)
		(end 305.998118 -293.421054)
		(width 0.18288)
		(layer "In6.Cu")
		(net "M_C_CPU0_SA_DQ<10>")
	)
	(segment
		(start 342.970104 -272.14449)
		(end 342.961214 -272.14957)
		(width 0.088646)
		(layer "In6.Cu")
		(net "M_C_CPU0_SA_DQ<10>")
	)
	(segment
		(start 295.691814 -297.839638)
		(end 295.508934 -298.022518)
		(width 0.18288)
		(layer "In6.Cu")
		(net "M_C_CPU0_SA_DQ<10>")
	)
	(segment
		(start 303.214024 -295.204896)
		(end 302.349662 -296.069258)
		(width 0.18288)
		(layer "In6.Cu")
		(net "M_C_CPU0_SA_DQ<10>")
	)
	(segment
		(start 305.343052 -293.218108)
		(end 304.869596 -293.691564)
		(width 0.18288)
		(layer "In6.Cu")
		(net "M_C_CPU0_SA_DQ<10>")
	)
	(segment
		(start 303.214024 -294.435784)
		(end 303.214024 -295.204896)
		(width 0.18288)
		(layer "In6.Cu")
		(net "M_C_CPU0_SA_DQ<10>")
	)
	(segment
		(start 302.349662 -296.069258)
		(end 302.09109 -296.069258)
		(width 0.18288)
		(layer "In6.Cu")
		(net "M_C_CPU0_SA_DQ<10>")
	)
	(segment
		(start 342.036146 -272.140934)
		(end 342.021414 -272.14957)
		(width 0.088646)
		(layer "In6.Cu")
		(net "M_C_CPU0_SA_DQ<10>")
	)
	(segment
		(start 294.027352 -298.891706)
		(end 293.16807 -299.750988)
		(width 0.18288)
		(layer "In6.Cu")
		(net "M_C_CPU0_SA_DQ<10>")
	)
	(segment
		(start 290.139882 -304.18405)
		(end 288.597594 -304.18405)
		(width 0.18288)
		(layer "In6.Cu")
		(net "M_C_CPU0_SA_DQ<10>")
	)
	(segment
		(start 343.148666 -271.809718)
		(end 343.148666 -271.825212)
		(width 0.088646)
		(layer "In6.Cu")
		(net "M_C_CPU0_SA_DQ<10>")
	)
	(segment
		(start 301.226982 -297.191938)
		(end 298.702476 -297.191938)
		(width 0.18288)
		(layer "In6.Cu")
		(net "M_C_CPU0_SA_DQ<10>")
	)
	(segment
		(start 336.948018 -272.14957)
		(end 336.937604 -272.143474)
		(width 0.088646)
		(layer "In6.Cu")
		(net "M_C_CPU0_SA_DQ<10>")
	)
	(segment
		(start 333.226918 -274.346924)
		(end 332.762352 -274.81149)
		(width 0.088646)
		(layer "In6.Cu")
		(net "M_C_CPU0_SA_DQ<10>")
	)
	(segment
		(start 295.508934 -298.708826)
		(end 295.326054 -298.891706)
		(width 0.18288)
		(layer "In6.Cu")
		(net "M_C_CPU0_SA_DQ<10>")
	)
	(segment
		(start 301.602394 -296.557954)
		(end 301.602394 -296.816526)
		(width 0.18288)
		(layer "In6.Cu")
		(net "M_C_CPU0_SA_DQ<10>")
	)
	(segment
		(start 305.569112 -293.218108)
		(end 305.343052 -293.218108)
		(width 0.18288)
		(layer "In6.Cu")
		(net "M_C_CPU0_SA_DQ<10>")
	)
	(segment
		(start 335.92135 -272.95856)
		(end 335.91246 -272.96364)
		(width 0.088646)
		(layer "In6.Cu")
		(net "M_C_CPU0_SA_DQ<10>")
	)
	(segment
		(start 332.762352 -274.81149)
		(end 332.434946 -274.81149)
		(width 0.088646)
		(layer "In6.Cu")
		(net "M_C_CPU0_SA_DQ<10>")
	)
	(segment
		(start 298.702476 -297.191938)
		(end 297.002708 -298.891706)
		(width 0.18288)
		(layer "In6.Cu")
		(net "M_C_CPU0_SA_DQ<10>")
	)
	(segment
		(start 312.258202 -291.037518)
		(end 310.79948 -291.037518)
		(width 0.18288)
		(layer "In6.Cu")
		(net "M_C_CPU0_SA_DQ<10>")
	)
	(segment
		(start 334.972914 -272.96364)
		(end 334.966818 -272.967196)
		(width 0.088646)
		(layer "In6.Cu")
		(net "M_C_CPU0_SA_DQ<10>")
	)
	(segment
		(start 304.869596 -293.691564)
		(end 303.958244 -293.691564)
		(width 0.18288)
		(layer "In6.Cu")
		(net "M_C_CPU0_SA_DQ<10>")
	)
	(segment
		(start 302.09109 -296.069258)
		(end 301.877476 -295.855644)
		(width 0.18288)
		(layer "In6.Cu")
		(net "M_C_CPU0_SA_DQ<10>")
	)
	(segment
		(start 308.940454 -291.798756)
		(end 308.288944 -291.798756)
		(width 0.18288)
		(layer "In6.Cu")
		(net "M_C_CPU0_SA_DQ<10>")
	)
	(segment
		(start 337.332828 -272.143474)
		(end 337.322414 -272.14957)
		(width 0.088646)
		(layer "In6.Cu")
		(net "M_C_CPU0_SA_DQ<10>")
	)
	(segment
		(start 296.016934 -297.839638)
		(end 295.691814 -297.839638)
		(width 0.18288)
		(layer "In6.Cu")
		(net "M_C_CPU0_SA_DQ<10>")
	)
	(segment
		(start 284.367732 -306.567586)
		(end 283.916882 -306.116736)
		(width 0.18288)
		(layer "In6.Cu")
		(net "M_C_CPU0_SA_DQ<10>")
	)
	(segment
		(start 297.002708 -298.891706)
		(end 296.382694 -298.891706)
		(width 0.18288)
		(layer "In6.Cu")
		(net "M_C_CPU0_SA_DQ<10>")
	)
	(segment
		(start 309.720488 -292.11651)
		(end 309.258208 -292.11651)
		(width 0.18288)
		(layer "In6.Cu")
		(net "M_C_CPU0_SA_DQ<10>")
	)
	(segment
		(start 327.087738 -277.33117)
		(end 315.146436 -289.27298)
		(width 0.18288)
		(layer "In6.Cu")
		(net "M_C_CPU0_SA_DQ<10>")
	)
	(segment
		(start 306.262532 -292.93058)
		(end 306.262532 -293.15664)
		(width 0.18288)
		(layer "In6.Cu")
		(net "M_C_CPU0_SA_DQ<10>")
	)
	(segment
		(start 301.38878 -296.34434)
		(end 301.602394 -296.557954)
		(width 0.18288)
		(layer "In6.Cu")
		(net "M_C_CPU0_SA_DQ<10>")
	)
	(segment
		(start 293.16807 -302.075342)
		(end 292.2651 -302.978312)
		(width 0.18288)
		(layer "In6.Cu")
		(net "M_C_CPU0_SA_DQ<10>")
	)
	(segment
		(start 339.212174 -272.143474)
		(end 339.20176 -272.14957)
		(width 0.088646)
		(layer "In6.Cu")
		(net "M_C_CPU0_SA_DQ<10>")
	)
	(segment
		(start 301.877476 -295.855644)
		(end 301.618904 -295.855644)
		(width 0.18288)
		(layer "In6.Cu")
		(net "M_C_CPU0_SA_DQ<10>")
	)
	(segment
		(start 305.998118 -293.421054)
		(end 305.772058 -293.421054)
		(width 0.18288)
		(layer "In6.Cu")
		(net "M_C_CPU0_SA_DQ<10>")
	)
	(segment
		(start 285.358078 -306.567586)
		(end 284.367732 -306.567586)
		(width 0.18288)
		(layer "In6.Cu")
		(net "M_C_CPU0_SA_DQ<10>")
	)
	(segment
		(start 288.597594 -304.18405)
		(end 287.87852 -304.903124)
		(width 0.18288)
		(layer "In6.Cu")
		(net "M_C_CPU0_SA_DQ<10>")
	)
	(segment
		(start 344.02649 -271.353026)
		(end 343.996264 -271.335754)
		(width 0.088646)
		(layer "In6.Cu")
		(net "M_C_CPU0_SA_DQ<10>")
	)
	(segment
		(start 331.514704 -275.731732)
		(end 331.283056 -275.731732)
		(width 0.088646)
		(layer "In6.Cu")
		(net "M_C_CPU0_SA_DQ<10>")
	)
	(segment
		(start 341.096346 -272.140934)
		(end 341.081614 -272.14957)
		(width 0.088646)
		(layer "In6.Cu")
		(net "M_C_CPU0_SA_DQ<10>")
	)
	(segment
		(start 314.02274 -289.27298)
		(end 312.258202 -291.037518)
		(width 0.18288)
		(layer "In6.Cu")
		(net "M_C_CPU0_SA_DQ<10>")
	)
	(segment
		(start 332.434946 -274.81149)
		(end 331.514704 -275.731732)
		(width 0.088646)
		(layer "In6.Cu")
		(net "M_C_CPU0_SA_DQ<10>")
	)
	(segment
		(start 292.2651 -302.978312)
		(end 291.34562 -302.978312)
		(width 0.18288)
		(layer "In6.Cu")
		(net "M_C_CPU0_SA_DQ<10>")
	)
	(segment
		(start 295.326054 -298.891706)
		(end 294.027352 -298.891706)
		(width 0.18288)
		(layer "In6.Cu")
		(net "M_C_CPU0_SA_DQ<10>")
	)
	(segment
		(start 343.996264 -271.335754)
		(end 343.981532 -271.327118)
		(width 0.088646)
		(layer "In6.Cu")
		(net "M_C_CPU0_SA_DQ<10>")
	)
	(segment
		(start 334.983328 -272.957544)
		(end 334.972914 -272.96364)
		(width 0.088646)
		(layer "In6.Cu")
		(net "M_C_CPU0_SA_DQ<10>")
	)
	(segment
		(start 296.382694 -298.891706)
		(end 296.199814 -298.708826)
		(width 0.18288)
		(layer "In6.Cu")
		(net "M_C_CPU0_SA_DQ<10>")
	)
	(segment
		(start 344.653616 -271.825212)
		(end 344.02649 -271.353026)
		(width 0.088646)
		(layer "In6.Cu")
		(net "M_C_CPU0_SA_DQ<10>")
	)
	(segment
		(start 333.226918 -274.030186)
		(end 333.226918 -274.346924)
		(width 0.088646)
		(layer "In6.Cu")
		(net "M_C_CPU0_SA_DQ<10>")
	)
	(segment
		(start 330.9493 -275.731732)
		(end 327.087738 -277.33117)
		(width 0.18288)
		(layer "In6.Cu")
		(net "M_C_CPU0_SA_DQ<10>")
	)
	(segment
		(start 301.602394 -296.816526)
		(end 301.226982 -297.191938)
		(width 0.18288)
		(layer "In6.Cu")
		(net "M_C_CPU0_SA_DQ<10>")
	)
	(segment
		(start 336.099912 -272.625058)
		(end 336.099912 -272.639282)
		(width 0.088646)
		(layer "In6.Cu")
		(net "M_C_CPU0_SA_DQ<10>")
	)
	(segment
		(start 296.199814 -298.708826)
		(end 296.199814 -298.022518)
		(width 0.18288)
		(layer "In6.Cu")
		(net "M_C_CPU0_SA_DQ<10>")
	)
	(arc
		(start 341.081614 -272.14957)
		(mid 340.894416 -272.199713)
		(end 340.707218 -272.14957)
		(width 0.088646)
		(layer "In6.Cu")
		(net "M_C_CPU0_SA_DQ<10>")
	)
	(arc
		(start 337.887564 -272.14957)
		(mid 337.611005 -272.073861)
		(end 337.332828 -272.143474)
		(width 0.088646)
		(layer "In6.Cu")
		(net "M_C_CPU0_SA_DQ<10>")
	)
	(arc
		(start 334.503014 -273.777456)
		(mid 334.315816 -273.827599)
		(end 334.128618 -273.777456)
		(width 0.088646)
		(layer "In6.Cu")
		(net "M_C_CPU0_SA_DQ<10>")
	)
	(arc
		(start 338.812632 -272.140934)
		(mid 338.536191 -272.073768)
		(end 338.26196 -272.14957)
		(width 0.088646)
		(layer "In6.Cu")
		(net "M_C_CPU0_SA_DQ<10>")
	)
	(arc
		(start 334.690212 -273.461734)
		(mid 334.637942 -273.644099)
		(end 334.503014 -273.777456)
		(width 0.088646)
		(layer "In6.Cu")
		(net "M_C_CPU0_SA_DQ<10>")
	)
	(arc
		(start 343.981532 -271.327118)
		(mid 343.705057 -271.259798)
		(end 343.43086 -271.335754)
		(width 0.088646)
		(layer "In6.Cu")
		(net "M_C_CPU0_SA_DQ<10>")
	)
	(arc
		(start 337.322414 -272.14957)
		(mid 337.135216 -272.199713)
		(end 336.948018 -272.14957)
		(width 0.088646)
		(layer "In6.Cu")
		(net "M_C_CPU0_SA_DQ<10>")
	)
	(arc
		(start 339.20176 -272.14957)
		(mid 339.014562 -272.199713)
		(end 338.827364 -272.14957)
		(width 0.088646)
		(layer "In6.Cu")
		(net "M_C_CPU0_SA_DQ<10>")
	)
	(arc
		(start 340.707218 -272.14957)
		(mid 340.432989 -272.073645)
		(end 340.156546 -272.140934)
		(width 0.088646)
		(layer "In6.Cu")
		(net "M_C_CPU0_SA_DQ<10>")
	)
	(arc
		(start 334.128618 -273.777456)
		(mid 333.854419 -273.701621)
		(end 333.577946 -273.76882)
		(width 0.088646)
		(layer "In6.Cu")
		(net "M_C_CPU0_SA_DQ<10>")
	)
	(arc
		(start 342.021414 -272.14957)
		(mid 341.834216 -272.199713)
		(end 341.647018 -272.14957)
		(width 0.088646)
		(layer "In6.Cu")
		(net "M_C_CPU0_SA_DQ<10>")
	)
	(arc
		(start 336.937604 -272.143474)
		(mid 336.659172 -272.07366)
		(end 336.38236 -272.14957)
		(width 0.088646)
		(layer "In6.Cu")
		(net "M_C_CPU0_SA_DQ<10>")
	)
	(arc
		(start 334.966818 -272.967196)
		(mid 334.764231 -273.173547)
		(end 334.690212 -273.453098)
		(width 0.088646)
		(layer "In6.Cu")
		(net "M_C_CPU0_SA_DQ<10>")
	)
	(arc
		(start 333.563214 -273.777456)
		(mid 333.419238 -273.869272)
		(end 333.283814 -273.97329)
		(width 0.088646)
		(layer "In6.Cu")
		(net "M_C_CPU0_SA_DQ<10>")
	)
	(arc
		(start 340.141814 -272.14957)
		(mid 339.954616 -272.199713)
		(end 339.767418 -272.14957)
		(width 0.088646)
		(layer "In6.Cu")
		(net "M_C_CPU0_SA_DQ<10>")
	)
	(arc
		(start 336.38236 -272.14957)
		(mid 336.179055 -272.350436)
		(end 336.099912 -272.625058)
		(width 0.088646)
		(layer "In6.Cu")
		(net "M_C_CPU0_SA_DQ<10>")
	)
	(arc
		(start 335.538064 -272.96364)
		(mid 335.261505 -272.887897)
		(end 334.983328 -272.957544)
		(width 0.088646)
		(layer "In6.Cu")
		(net "M_C_CPU0_SA_DQ<10>")
	)
	(arc
		(start 342.961214 -272.14957)
		(mid 342.774016 -272.199713)
		(end 342.586818 -272.14957)
		(width 0.088646)
		(layer "In6.Cu")
		(net "M_C_CPU0_SA_DQ<10>")
	)
	(arc
		(start 343.148666 -271.825212)
		(mid 343.100987 -272.008112)
		(end 342.970104 -272.14449)
		(width 0.088646)
		(layer "In6.Cu")
		(net "M_C_CPU0_SA_DQ<10>")
	)
	(arc
		(start 341.647018 -272.14957)
		(mid 341.372789 -272.073645)
		(end 341.096346 -272.140934)
		(width 0.088646)
		(layer "In6.Cu")
		(net "M_C_CPU0_SA_DQ<10>")
	)
	(arc
		(start 342.586818 -272.14957)
		(mid 342.312589 -272.073645)
		(end 342.036146 -272.140934)
		(width 0.088646)
		(layer "In6.Cu")
		(net "M_C_CPU0_SA_DQ<10>")
	)
	(arc
		(start 335.91246 -272.96364)
		(mid 335.725262 -273.013783)
		(end 335.538064 -272.96364)
		(width 0.088646)
		(layer "In6.Cu")
		(net "M_C_CPU0_SA_DQ<10>")
	)
	(arc
		(start 338.26196 -272.14957)
		(mid 338.074762 -272.199713)
		(end 337.887564 -272.14957)
		(width 0.088646)
		(layer "In6.Cu")
		(net "M_C_CPU0_SA_DQ<10>")
	)
	(arc
		(start 336.099912 -272.639282)
		(mid 336.052233 -272.822182)
		(end 335.92135 -272.95856)
		(width 0.088646)
		(layer "In6.Cu")
		(net "M_C_CPU0_SA_DQ<10>")
	)
	(arc
		(start 339.767418 -272.14957)
		(mid 339.490605 -272.073734)
		(end 339.212174 -272.143474)
		(width 0.088646)
		(layer "In6.Cu")
		(net "M_C_CPU0_SA_DQ<10>")
	)
	(arc
		(start 343.43086 -271.335754)
		(mid 343.228037 -271.535985)
		(end 343.148666 -271.809718)
		(width 0.088646)
		(layer "In6.Cu")
		(net "M_C_CPU0_SA_DQ<10>")
	)
	(segment
		(start 276.917912 -315.891672)
		(end 276.469094 -315.891672)
		(width 0.20066)
		(layer "F.Cu")
		(net "M_C_CPU0_SA_DQ<0>")
	)
	(segment
		(start 273.37258 -316.093094)
		(end 273.37258 -316.382654)
		(width 0.20066)
		(layer "F.Cu")
		(net "M_C_CPU0_SA_DQ<0>")
	)
	(segment
		(start 273.58213 -315.883544)
		(end 273.37258 -316.093094)
		(width 0.20066)
		(layer "F.Cu")
		(net "M_C_CPU0_SA_DQ<0>")
	)
	(segment
		(start 274.40001 -315.891672)
		(end 274.152106 -315.891672)
		(width 0.101854)
		(layer "F.Cu")
		(net "M_C_CPU0_SA_DQ<0>")
	)
	(segment
		(start 273.19986 -316.555374)
		(end 272.741136 -316.555374)
		(width 0.20066)
		(layer "F.Cu")
		(net "M_C_CPU0_SA_DQ<0>")
	)
	(segment
		(start 278.711914 -316.316614)
		(end 277.342854 -316.316614)
		(width 0.20066)
		(layer "F.Cu")
		(net "M_C_CPU0_SA_DQ<0>")
	)
	(segment
		(start 272.741136 -316.555374)
		(end 272.502376 -316.316614)
		(width 0.20066)
		(layer "F.Cu")
		(net "M_C_CPU0_SA_DQ<0>")
	)
	(segment
		(start 279.816814 -316.316614)
		(end 278.711914 -316.316614)
		(width 0.20066)
		(layer "F.Cu")
		(net "M_C_CPU0_SA_DQ<0>")
	)
	(segment
		(start 274.143978 -315.883544)
		(end 273.58213 -315.883544)
		(width 0.20066)
		(layer "F.Cu")
		(net "M_C_CPU0_SA_DQ<0>")
	)
	(segment
		(start 276.469094 -315.891672)
		(end 274.40001 -315.891672)
		(width 0.1016)
		(layer "F.Cu")
		(net "M_C_CPU0_SA_DQ<0>")
	)
	(segment
		(start 340.424516 -278.614378)
		(end 340.424262 -279.150318)
		(width 0.20066)
		(layer "F.Cu")
		(net "M_C_CPU0_SA_DQ<0>")
	)
	(segment
		(start 272.502376 -316.316614)
		(end 271.168114 -316.316614)
		(width 0.20066)
		(layer "F.Cu")
		(net "M_C_CPU0_SA_DQ<0>")
	)
	(segment
		(start 274.152106 -315.891672)
		(end 274.143978 -315.883544)
		(width 0.101854)
		(layer "F.Cu")
		(net "M_C_CPU0_SA_DQ<0>")
	)
	(segment
		(start 277.342854 -316.316614)
		(end 276.917912 -315.891672)
		(width 0.20066)
		(layer "F.Cu")
		(net "M_C_CPU0_SA_DQ<0>")
	)
	(segment
		(start 273.37258 -316.382654)
		(end 273.19986 -316.555374)
		(width 0.20066)
		(layer "F.Cu")
		(net "M_C_CPU0_SA_DQ<0>")
	)
	(segment
		(start 306.215542 -317.719456)
		(end 305.953922 -317.457836)
		(width 0.18288)
		(layer "In4.Cu")
		(net "M_C_CPU0_SA_DQ<0>")
	)
	(segment
		(start 297.78452 -319.567052)
		(end 297.508676 -319.291208)
		(width 0.18288)
		(layer "In4.Cu")
		(net "M_C_CPU0_SA_DQ<0>")
	)
	(segment
		(start 291.758878 -318.441578)
		(end 287.826958 -318.441578)
		(width 0.18288)
		(layer "In4.Cu")
		(net "M_C_CPU0_SA_DQ<0>")
	)
	(segment
		(start 313.865006 -315.821314)
		(end 311.350406 -315.821314)
		(width 0.18288)
		(layer "In4.Cu")
		(net "M_C_CPU0_SA_DQ<0>")
	)
	(segment
		(start 308.068472 -317.50508)
		(end 307.563012 -317.71463)
		(width 0.18288)
		(layer "In4.Cu")
		(net "M_C_CPU0_SA_DQ<0>")
	)
	(segment
		(start 282.854146 -318.441578)
		(end 281.154124 -316.741556)
		(width 0.18288)
		(layer "In4.Cu")
		(net "M_C_CPU0_SA_DQ<0>")
	)
	(segment
		(start 301.829216 -318.182498)
		(end 301.397924 -318.36106)
		(width 0.18288)
		(layer "In4.Cu")
		(net "M_C_CPU0_SA_DQ<0>")
	)
	(segment
		(start 336.490056 -286.95777)
		(end 336.477864 -286.964882)
		(width 0.088646)
		(layer "In4.Cu")
		(net "M_C_CPU0_SA_DQ<0>")
	)
	(segment
		(start 334.427576 -288.400236)
		(end 334.129126 -288.400236)
		(width 0.088646)
		(layer "In4.Cu")
		(net "M_C_CPU0_SA_DQ<0>")
	)
	(segment
		(start 281.154124 -316.741556)
		(end 280.241756 -316.741556)
		(width 0.18288)
		(layer "In4.Cu")
		(net "M_C_CPU0_SA_DQ<0>")
	)
	(segment
		(start 337.700112 -284.847538)
		(end 337.700112 -284.857444)
		(width 0.088646)
		(layer "In4.Cu")
		(net "M_C_CPU0_SA_DQ<0>")
	)
	(segment
		(start 339.767164 -282.895548)
		(end 339.758274 -282.900628)
		(width 0.088646)
		(layer "In4.Cu")
		(net "M_C_CPU0_SA_DQ<0>")
	)
	(segment
		(start 336.290412 -287.28924)
		(end 336.290412 -287.299146)
		(width 0.088646)
		(layer "In4.Cu")
		(net "M_C_CPU0_SA_DQ<0>")
	)
	(segment
		(start 307.563012 -317.71463)
		(end 307.551074 -317.719456)
		(width 0.18288)
		(layer "In4.Cu")
		(net "M_C_CPU0_SA_DQ<0>")
	)
	(segment
		(start 286.813498 -318.441578)
		(end 282.854146 -318.441578)
		(width 0.18288)
		(layer "In4.Cu")
		(net "M_C_CPU0_SA_DQ<0>")
	)
	(segment
		(start 336.948018 -286.151066)
		(end 336.939128 -286.156146)
		(width 0.088646)
		(layer "In4.Cu")
		(net "M_C_CPU0_SA_DQ<0>")
	)
	(segment
		(start 310.720232 -316.451488)
		(end 310.259222 -316.642496)
		(width 0.18288)
		(layer "In4.Cu")
		(net "M_C_CPU0_SA_DQ<0>")
	)
	(segment
		(start 301.397924 -318.36106)
		(end 300.505114 -319.25387)
		(width 0.18288)
		(layer "In4.Cu")
		(net "M_C_CPU0_SA_DQ<0>")
	)
	(segment
		(start 340.424262 -279.150318)
		(end 340.446614 -279.16759)
		(width 0.088646)
		(layer "In4.Cu")
		(net "M_C_CPU0_SA_DQ<0>")
	)
	(segment
		(start 286.973518 -318.281558)
		(end 286.813498 -318.441578)
		(width 0.18288)
		(layer "In4.Cu")
		(net "M_C_CPU0_SA_DQ<0>")
	)
	(segment
		(start 340.519766 -279.766268)
		(end 340.519766 -279.982676)
		(width 0.088646)
		(layer "In4.Cu")
		(net "M_C_CPU0_SA_DQ<0>")
	)
	(segment
		(start 310.259222 -316.642496)
		(end 309.564024 -316.642496)
		(width 0.18288)
		(layer "In4.Cu")
		(net "M_C_CPU0_SA_DQ<0>")
	)
	(segment
		(start 334.129126 -288.400236)
		(end 333.81823 -288.400236)
		(width 0.18288)
		(layer "In4.Cu")
		(net "M_C_CPU0_SA_DQ<0>")
	)
	(segment
		(start 340.519512 -281.576526)
		(end 340.519512 -281.607514)
		(width 0.088646)
		(layer "In4.Cu")
		(net "M_C_CPU0_SA_DQ<0>")
	)
	(segment
		(start 309.564024 -316.642496)
		(end 309.148988 -317.057532)
		(width 0.18288)
		(layer "In4.Cu")
		(net "M_C_CPU0_SA_DQ<0>")
	)
	(segment
		(start 299.835824 -319.25387)
		(end 299.522642 -319.567052)
		(width 0.18288)
		(layer "In4.Cu")
		(net "M_C_CPU0_SA_DQ<0>")
	)
	(segment
		(start 340.049866 -282.405836)
		(end 340.049866 -282.42006)
		(width 0.088646)
		(layer "In4.Cu")
		(net "M_C_CPU0_SA_DQ<0>")
	)
	(segment
		(start 287.826958 -318.441578)
		(end 287.666938 -318.281558)
		(width 0.18288)
		(layer "In4.Cu")
		(net "M_C_CPU0_SA_DQ<0>")
	)
	(segment
		(start 340.237318 -280.453846)
		(end 340.228428 -280.458926)
		(width 0.088646)
		(layer "In4.Cu")
		(net "M_C_CPU0_SA_DQ<0>")
	)
	(segment
		(start 287.506918 -317.791592)
		(end 287.133538 -317.791592)
		(width 0.18288)
		(layer "In4.Cu")
		(net "M_C_CPU0_SA_DQ<0>")
	)
	(segment
		(start 297.508676 -319.291208)
		(end 294.062912 -319.291208)
		(width 0.18288)
		(layer "In4.Cu")
		(net "M_C_CPU0_SA_DQ<0>")
	)
	(segment
		(start 280.241756 -316.741556)
		(end 279.816814 -316.316614)
		(width 0.18288)
		(layer "In4.Cu")
		(net "M_C_CPU0_SA_DQ<0>")
	)
	(segment
		(start 287.666938 -317.951612)
		(end 287.506918 -317.791592)
		(width 0.18288)
		(layer "In4.Cu")
		(net "M_C_CPU0_SA_DQ<0>")
	)
	(segment
		(start 311.350406 -315.821314)
		(end 310.720232 -316.451488)
		(width 0.18288)
		(layer "In4.Cu")
		(net "M_C_CPU0_SA_DQ<0>")
	)
	(segment
		(start 340.237318 -282.081478)
		(end 340.228428 -282.086558)
		(width 0.088646)
		(layer "In4.Cu")
		(net "M_C_CPU0_SA_DQ<0>")
	)
	(segment
		(start 336.477864 -286.964882)
		(end 336.468974 -286.969962)
		(width 0.088646)
		(layer "In4.Cu")
		(net "M_C_CPU0_SA_DQ<0>")
	)
	(segment
		(start 303.42459 -318.182498)
		(end 301.829216 -318.182498)
		(width 0.18288)
		(layer "In4.Cu")
		(net "M_C_CPU0_SA_DQ<0>")
	)
	(segment
		(start 337.417664 -285.336996)
		(end 337.408774 -285.342076)
		(width 0.088646)
		(layer "In4.Cu")
		(net "M_C_CPU0_SA_DQ<0>")
	)
	(segment
		(start 328.496676 -298.77131)
		(end 322.014342 -305.253644)
		(width 0.18288)
		(layer "In4.Cu")
		(net "M_C_CPU0_SA_DQ<0>")
	)
	(segment
		(start 304.149252 -317.457836)
		(end 303.42459 -318.182498)
		(width 0.18288)
		(layer "In4.Cu")
		(net "M_C_CPU0_SA_DQ<0>")
	)
	(segment
		(start 332.06817 -290.150296)
		(end 328.496676 -298.77131)
		(width 0.18288)
		(layer "In4.Cu")
		(net "M_C_CPU0_SA_DQ<0>")
	)
	(segment
		(start 322.014342 -307.671978)
		(end 313.865006 -315.821314)
		(width 0.18288)
		(layer "In4.Cu")
		(net "M_C_CPU0_SA_DQ<0>")
	)
	(segment
		(start 287.133538 -317.791592)
		(end 286.973518 -317.951612)
		(width 0.18288)
		(layer "In4.Cu")
		(net "M_C_CPU0_SA_DQ<0>")
	)
	(segment
		(start 333.81823 -288.400236)
		(end 332.06817 -290.150296)
		(width 0.18288)
		(layer "In4.Cu")
		(net "M_C_CPU0_SA_DQ<0>")
	)
	(segment
		(start 339.579712 -283.219906)
		(end 339.579712 -283.229812)
		(width 0.088646)
		(layer "In4.Cu")
		(net "M_C_CPU0_SA_DQ<0>")
	)
	(segment
		(start 299.522642 -319.567052)
		(end 297.78452 -319.567052)
		(width 0.18288)
		(layer "In4.Cu")
		(net "M_C_CPU0_SA_DQ<0>")
	)
	(segment
		(start 339.109812 -284.033722)
		(end 339.109812 -284.043628)
		(width 0.088646)
		(layer "In4.Cu")
		(net "M_C_CPU0_SA_DQ<0>")
	)
	(segment
		(start 339.297264 -283.709364)
		(end 339.288374 -283.714444)
		(width 0.088646)
		(layer "In4.Cu")
		(net "M_C_CPU0_SA_DQ<0>")
	)
	(segment
		(start 287.666938 -318.281558)
		(end 287.666938 -317.951612)
		(width 0.18288)
		(layer "In4.Cu")
		(net "M_C_CPU0_SA_DQ<0>")
	)
	(segment
		(start 305.953922 -317.457836)
		(end 304.149252 -317.457836)
		(width 0.18288)
		(layer "In4.Cu")
		(net "M_C_CPU0_SA_DQ<0>")
	)
	(segment
		(start 309.148988 -317.057532)
		(end 308.068472 -317.50508)
		(width 0.18288)
		(layer "In4.Cu")
		(net "M_C_CPU0_SA_DQ<0>")
	)
	(segment
		(start 337.230212 -285.661354)
		(end 337.230212 -285.683452)
		(width 0.088646)
		(layer "In4.Cu")
		(net "M_C_CPU0_SA_DQ<0>")
	)
	(segment
		(start 294.062912 -319.291208)
		(end 291.758878 -318.441578)
		(width 0.18288)
		(layer "In4.Cu")
		(net "M_C_CPU0_SA_DQ<0>")
	)
	(segment
		(start 322.014342 -305.253644)
		(end 322.014342 -307.671978)
		(width 0.18288)
		(layer "In4.Cu")
		(net "M_C_CPU0_SA_DQ<0>")
	)
	(segment
		(start 300.505114 -319.25387)
		(end 299.835824 -319.25387)
		(width 0.18288)
		(layer "In4.Cu")
		(net "M_C_CPU0_SA_DQ<0>")
	)
	(segment
		(start 340.446614 -279.16759)
		(end 340.519766 -279.766268)
		(width 0.088646)
		(layer "In4.Cu")
		(net "M_C_CPU0_SA_DQ<0>")
	)
	(segment
		(start 286.973518 -317.951612)
		(end 286.973518 -318.281558)
		(width 0.18288)
		(layer "In4.Cu")
		(net "M_C_CPU0_SA_DQ<0>")
	)
	(segment
		(start 334.990186 -287.838134)
		(end 334.427576 -288.400236)
		(width 0.088646)
		(layer "In4.Cu")
		(net "M_C_CPU0_SA_DQ<0>")
	)
	(segment
		(start 307.551074 -317.719456)
		(end 306.215542 -317.719456)
		(width 0.18288)
		(layer "In4.Cu")
		(net "M_C_CPU0_SA_DQ<0>")
	)
	(segment
		(start 337.887564 -284.52318)
		(end 337.878674 -284.52826)
		(width 0.088646)
		(layer "In4.Cu")
		(net "M_C_CPU0_SA_DQ<0>")
	)
	(segment
		(start 340.228428 -281.097482)
		(end 340.237318 -281.102562)
		(width 0.088646)
		(layer "In4.Cu")
		(net "M_C_CPU0_SA_DQ<0>")
	)
	(segment
		(start 335.44256 -287.778698)
		(end 335.442814 -287.778444)
		(width 0.088646)
		(layer "In4.Cu")
		(net "M_C_CPU0_SA_DQ<0>")
	)
	(arc
		(start 336.468974 -286.969962)
		(mid 336.33806 -287.106322)
		(end 336.290412 -287.28924)
		(width 0.088646)
		(layer "In4.Cu")
		(net "M_C_CPU0_SA_DQ<0>")
	)
	(arc
		(start 340.228428 -280.458926)
		(mid 340.049831 -280.778204)
		(end 340.228428 -281.097482)
		(width 0.088646)
		(layer "In4.Cu")
		(net "M_C_CPU0_SA_DQ<0>")
	)
	(arc
		(start 340.237318 -281.102562)
		(mid 340.440141 -281.302793)
		(end 340.519512 -281.576526)
		(width 0.088646)
		(layer "In4.Cu")
		(net "M_C_CPU0_SA_DQ<0>")
	)
	(arc
		(start 337.700112 -284.857444)
		(mid 337.622001 -285.134393)
		(end 337.417664 -285.336996)
		(width 0.088646)
		(layer "In4.Cu")
		(net "M_C_CPU0_SA_DQ<0>")
	)
	(arc
		(start 339.109812 -284.043628)
		(mid 339.031701 -284.320577)
		(end 338.827364 -284.52318)
		(width 0.088646)
		(layer "In4.Cu")
		(net "M_C_CPU0_SA_DQ<0>")
	)
	(arc
		(start 339.579712 -283.229812)
		(mid 339.501601 -283.506761)
		(end 339.297264 -283.709364)
		(width 0.088646)
		(layer "In4.Cu")
		(net "M_C_CPU0_SA_DQ<0>")
	)
	(arc
		(start 335.067656 -287.778444)
		(mid 335.026969 -287.805755)
		(end 334.990186 -287.838134)
		(width 0.088646)
		(layer "In4.Cu")
		(net "M_C_CPU0_SA_DQ<0>")
	)
	(arc
		(start 337.408774 -285.342076)
		(mid 337.27786 -285.478436)
		(end 337.230212 -285.661354)
		(width 0.088646)
		(layer "In4.Cu")
		(net "M_C_CPU0_SA_DQ<0>")
	)
	(arc
		(start 336.290412 -287.299146)
		(mid 336.212301 -287.576095)
		(end 336.007964 -287.778698)
		(width 0.088646)
		(layer "In4.Cu")
		(net "M_C_CPU0_SA_DQ<0>")
	)
	(arc
		(start 335.442814 -287.778444)
		(mid 335.255252 -287.728208)
		(end 335.067656 -287.778444)
		(width 0.088646)
		(layer "In4.Cu")
		(net "M_C_CPU0_SA_DQ<0>")
	)
	(arc
		(start 340.519512 -281.607514)
		(mid 340.440142 -281.881248)
		(end 340.237318 -282.081478)
		(width 0.088646)
		(layer "In4.Cu")
		(net "M_C_CPU0_SA_DQ<0>")
	)
	(arc
		(start 336.939128 -286.156146)
		(mid 336.808214 -286.292506)
		(end 336.760566 -286.475424)
		(width 0.088646)
		(layer "In4.Cu")
		(net "M_C_CPU0_SA_DQ<0>")
	)
	(arc
		(start 340.228428 -282.086558)
		(mid 340.097514 -282.222918)
		(end 340.049866 -282.405836)
		(width 0.088646)
		(layer "In4.Cu")
		(net "M_C_CPU0_SA_DQ<0>")
	)
	(arc
		(start 340.049866 -282.42006)
		(mid 339.970647 -282.694745)
		(end 339.767164 -282.895548)
		(width 0.088646)
		(layer "In4.Cu")
		(net "M_C_CPU0_SA_DQ<0>")
	)
	(arc
		(start 336.760566 -286.475424)
		(mid 336.688331 -286.751948)
		(end 336.490056 -286.95777)
		(width 0.088646)
		(layer "In4.Cu")
		(net "M_C_CPU0_SA_DQ<0>")
	)
	(arc
		(start 338.827364 -284.52318)
		(mid 338.544662 -284.598956)
		(end 338.26196 -284.52318)
		(width 0.088646)
		(layer "In4.Cu")
		(net "M_C_CPU0_SA_DQ<0>")
	)
	(arc
		(start 338.26196 -284.52318)
		(mid 338.074762 -284.473037)
		(end 337.887564 -284.52318)
		(width 0.088646)
		(layer "In4.Cu")
		(net "M_C_CPU0_SA_DQ<0>")
	)
	(arc
		(start 337.230212 -285.683452)
		(mid 337.149301 -285.95358)
		(end 336.948018 -286.151066)
		(width 0.088646)
		(layer "In4.Cu")
		(net "M_C_CPU0_SA_DQ<0>")
	)
	(arc
		(start 337.878674 -284.52826)
		(mid 337.74776 -284.66462)
		(end 337.700112 -284.847538)
		(width 0.088646)
		(layer "In4.Cu")
		(net "M_C_CPU0_SA_DQ<0>")
	)
	(arc
		(start 339.758274 -282.900628)
		(mid 339.62736 -283.036988)
		(end 339.579712 -283.219906)
		(width 0.088646)
		(layer "In4.Cu")
		(net "M_C_CPU0_SA_DQ<0>")
	)
	(arc
		(start 336.007964 -287.778698)
		(mid 335.725262 -287.854474)
		(end 335.44256 -287.778698)
		(width 0.088646)
		(layer "In4.Cu")
		(net "M_C_CPU0_SA_DQ<0>")
	)
	(arc
		(start 339.288374 -283.714444)
		(mid 339.15746 -283.850804)
		(end 339.109812 -284.033722)
		(width 0.088646)
		(layer "In4.Cu")
		(net "M_C_CPU0_SA_DQ<0>")
	)
	(arc
		(start 340.519766 -279.982676)
		(mid 340.439604 -280.254865)
		(end 340.237318 -280.453846)
		(width 0.088646)
		(layer "In4.Cu")
		(net "M_C_CPU0_SA_DQ<0>")
	)
	(segment
		(start 283.916882 -267.016738)
		(end 282.811982 -267.016738)
		(width 0.20066)
		(layer "F.Cu")
		(net "M_C_CPU0_SA_CS_N<3>")
	)
	(segment
		(start 341.833962 -258.802886)
		(end 341.834216 -258.80314)
		(width 0.20066)
		(layer "F.Cu")
		(net "M_C_CPU0_SA_CS_N<3>")
	)
	(segment
		(start 341.833962 -258.2672)
		(end 341.833962 -258.802886)
		(width 0.20066)
		(layer "F.Cu")
		(net "M_C_CPU0_SA_CS_N<3>")
	)
	(segment
		(start 338.827364 -257.499612)
		(end 338.812632 -257.490976)
		(width 0.088646)
		(layer "In4.Cu")
		(net "M_C_CPU0_SA_CS_N<3>")
	)
	(segment
		(start 304.370232 -265.741658)
		(end 292.58641 -265.741658)
		(width 0.18288)
		(layer "In4.Cu")
		(net "M_C_CPU0_SA_CS_N<3>")
	)
	(segment
		(start 333.022448 -257.550158)
		(end 332.78826 -257.31597)
		(width 0.088646)
		(layer "In4.Cu")
		(net "M_C_CPU0_SA_CS_N<3>")
	)
	(segment
		(start 304.735992 -264.992104)
		(end 304.553112 -265.174984)
		(width 0.18288)
		(layer "In4.Cu")
		(net "M_C_CPU0_SA_CS_N<3>")
	)
	(segment
		(start 331.637132 -257.31597)
		(end 330.769722 -258.18338)
		(width 0.18288)
		(layer "In4.Cu")
		(net "M_C_CPU0_SA_CS_N<3>")
	)
	(segment
		(start 313.004454 -263.424162)
		(end 312.564272 -263.864344)
		(width 0.18288)
		(layer "In4.Cu")
		(net "M_C_CPU0_SA_CS_N<3>")
	)
	(segment
		(start 332.375002 -257.31597)
		(end 331.637132 -257.31597)
		(width 0.18288)
		(layer "In4.Cu")
		(net "M_C_CPU0_SA_CS_N<3>")
	)
	(segment
		(start 330.769722 -258.18338)
		(end 324.409816 -258.18338)
		(width 0.18288)
		(layer "In4.Cu")
		(net "M_C_CPU0_SA_CS_N<3>")
	)
	(segment
		(start 314.306966 -263.424162)
		(end 313.004454 -263.424162)
		(width 0.18288)
		(layer "In4.Cu")
		(net "M_C_CPU0_SA_CS_N<3>")
	)
	(segment
		(start 305.246532 -265.174984)
		(end 305.063652 -264.992104)
		(width 0.18288)
		(layer "In4.Cu")
		(net "M_C_CPU0_SA_CS_N<3>")
	)
	(segment
		(start 340.815676 -258.381246)
		(end 339.550502 -258.381246)
		(width 0.088646)
		(layer "In4.Cu")
		(net "M_C_CPU0_SA_CS_N<3>")
	)
	(segment
		(start 306.408074 -265.741658)
		(end 305.429412 -265.741658)
		(width 0.18288)
		(layer "In4.Cu")
		(net "M_C_CPU0_SA_CS_N<3>")
	)
	(segment
		(start 304.553112 -265.174984)
		(end 304.553112 -265.558778)
		(width 0.18288)
		(layer "In4.Cu")
		(net "M_C_CPU0_SA_CS_N<3>")
	)
	(segment
		(start 307.485796 -264.663936)
		(end 306.408074 -265.741658)
		(width 0.18288)
		(layer "In4.Cu")
		(net "M_C_CPU0_SA_CS_N<3>")
	)
	(segment
		(start 310.95315 -264.663936)
		(end 307.485796 -264.663936)
		(width 0.18288)
		(layer "In4.Cu")
		(net "M_C_CPU0_SA_CS_N<3>")
	)
	(segment
		(start 292.58641 -265.741658)
		(end 291.735764 -266.592304)
		(width 0.18288)
		(layer "In4.Cu")
		(net "M_C_CPU0_SA_CS_N<3>")
	)
	(segment
		(start 288.56178 -266.592304)
		(end 287.71088 -267.443204)
		(width 0.18288)
		(layer "In4.Cu")
		(net "M_C_CPU0_SA_CS_N<3>")
	)
	(segment
		(start 291.735764 -266.592304)
		(end 288.56178 -266.592304)
		(width 0.18288)
		(layer "In4.Cu")
		(net "M_C_CPU0_SA_CS_N<3>")
	)
	(segment
		(start 284.343348 -267.443204)
		(end 283.916882 -267.016738)
		(width 0.18288)
		(layer "In4.Cu")
		(net "M_C_CPU0_SA_CS_N<3>")
	)
	(segment
		(start 311.752742 -263.864344)
		(end 310.95315 -264.663936)
		(width 0.18288)
		(layer "In4.Cu")
		(net "M_C_CPU0_SA_CS_N<3>")
	)
	(segment
		(start 305.429412 -265.741658)
		(end 305.246532 -265.558778)
		(width 0.18288)
		(layer "In4.Cu")
		(net "M_C_CPU0_SA_CS_N<3>")
	)
	(segment
		(start 332.78826 -257.31597)
		(end 332.375002 -257.31597)
		(width 0.088646)
		(layer "In4.Cu")
		(net "M_C_CPU0_SA_CS_N<3>")
	)
	(segment
		(start 324.409816 -258.18338)
		(end 316.087252 -261.643876)
		(width 0.18288)
		(layer "In4.Cu")
		(net "M_C_CPU0_SA_CS_N<3>")
	)
	(segment
		(start 305.063652 -264.992104)
		(end 304.735992 -264.992104)
		(width 0.18288)
		(layer "In4.Cu")
		(net "M_C_CPU0_SA_CS_N<3>")
	)
	(segment
		(start 305.246532 -265.558778)
		(end 305.246532 -265.174984)
		(width 0.18288)
		(layer "In4.Cu")
		(net "M_C_CPU0_SA_CS_N<3>")
	)
	(segment
		(start 338.83346 -257.503168)
		(end 338.827364 -257.499612)
		(width 0.088646)
		(layer "In4.Cu")
		(net "M_C_CPU0_SA_CS_N<3>")
	)
	(segment
		(start 333.375762 -257.550158)
		(end 333.022448 -257.550158)
		(width 0.088646)
		(layer "In4.Cu")
		(net "M_C_CPU0_SA_CS_N<3>")
	)
	(segment
		(start 339.110066 -257.997706)
		(end 339.110066 -257.98907)
		(width 0.088646)
		(layer "In4.Cu")
		(net "M_C_CPU0_SA_CS_N<3>")
	)
	(segment
		(start 312.564272 -263.864344)
		(end 311.752742 -263.864344)
		(width 0.18288)
		(layer "In4.Cu")
		(net "M_C_CPU0_SA_CS_N<3>")
	)
	(segment
		(start 304.553112 -265.558778)
		(end 304.370232 -265.741658)
		(width 0.18288)
		(layer "In4.Cu")
		(net "M_C_CPU0_SA_CS_N<3>")
	)
	(segment
		(start 287.71088 -267.443204)
		(end 284.343348 -267.443204)
		(width 0.18288)
		(layer "In4.Cu")
		(net "M_C_CPU0_SA_CS_N<3>")
	)
	(segment
		(start 316.087252 -261.643876)
		(end 314.306966 -263.424162)
		(width 0.18288)
		(layer "In4.Cu")
		(net "M_C_CPU0_SA_CS_N<3>")
	)
	(arc
		(start 338.812632 -257.490976)
		(mid 338.536157 -257.423656)
		(end 338.26196 -257.499612)
		(width 0.088646)
		(layer "In4.Cu")
		(net "M_C_CPU0_SA_CS_N<3>")
	)
	(arc
		(start 334.50276 -257.499612)
		(mid 334.315562 -257.549755)
		(end 334.128364 -257.499612)
		(width 0.088646)
		(layer "In4.Cu")
		(net "M_C_CPU0_SA_CS_N<3>")
	)
	(arc
		(start 336.947764 -257.499612)
		(mid 336.665062 -257.423836)
		(end 336.38236 -257.499612)
		(width 0.088646)
		(layer "In4.Cu")
		(net "M_C_CPU0_SA_CS_N<3>")
	)
	(arc
		(start 333.56296 -257.499612)
		(mid 333.472688 -257.537211)
		(end 333.375762 -257.550158)
		(width 0.088646)
		(layer "In4.Cu")
		(net "M_C_CPU0_SA_CS_N<3>")
	)
	(arc
		(start 339.297264 -258.313428)
		(mid 339.162331 -258.180074)
		(end 339.110066 -257.997706)
		(width 0.088646)
		(layer "In4.Cu")
		(net "M_C_CPU0_SA_CS_N<3>")
	)
	(arc
		(start 337.32216 -257.499612)
		(mid 337.134962 -257.549755)
		(end 336.947764 -257.499612)
		(width 0.088646)
		(layer "In4.Cu")
		(net "M_C_CPU0_SA_CS_N<3>")
	)
	(arc
		(start 338.26196 -257.499612)
		(mid 338.074762 -257.549755)
		(end 337.887564 -257.499612)
		(width 0.088646)
		(layer "In4.Cu")
		(net "M_C_CPU0_SA_CS_N<3>")
	)
	(arc
		(start 339.110066 -257.98907)
		(mid 339.036075 -257.709504)
		(end 338.83346 -257.503168)
		(width 0.088646)
		(layer "In4.Cu")
		(net "M_C_CPU0_SA_CS_N<3>")
	)
	(arc
		(start 335.44256 -257.499612)
		(mid 335.255362 -257.549755)
		(end 335.068164 -257.499612)
		(width 0.088646)
		(layer "In4.Cu")
		(net "M_C_CPU0_SA_CS_N<3>")
	)
	(arc
		(start 336.38236 -257.499612)
		(mid 336.195162 -257.549755)
		(end 336.007964 -257.499612)
		(width 0.088646)
		(layer "In4.Cu")
		(net "M_C_CPU0_SA_CS_N<3>")
	)
	(arc
		(start 334.128364 -257.499612)
		(mid 333.845662 -257.423836)
		(end 333.56296 -257.499612)
		(width 0.088646)
		(layer "In4.Cu")
		(net "M_C_CPU0_SA_CS_N<3>")
	)
	(arc
		(start 335.068164 -257.499612)
		(mid 334.785462 -257.423836)
		(end 334.50276 -257.499612)
		(width 0.088646)
		(layer "In4.Cu")
		(net "M_C_CPU0_SA_CS_N<3>")
	)
	(arc
		(start 336.007964 -257.499612)
		(mid 335.725262 -257.423836)
		(end 335.44256 -257.499612)
		(width 0.088646)
		(layer "In4.Cu")
		(net "M_C_CPU0_SA_CS_N<3>")
	)
	(arc
		(start 337.887564 -257.499612)
		(mid 337.604862 -257.423836)
		(end 337.32216 -257.499612)
		(width 0.088646)
		(layer "In4.Cu")
		(net "M_C_CPU0_SA_CS_N<3>")
	)
	(arc
		(start 341.834216 -258.80314)
		(mid 341.366906 -258.490893)
		(end 340.815676 -258.381246)
		(width 0.088646)
		(layer "In4.Cu")
		(net "M_C_CPU0_SA_CS_N<3>")
	)
	(arc
		(start 339.550502 -258.381246)
		(mid 339.419425 -258.363991)
		(end 339.297264 -258.313428)
		(width 0.088646)
		(layer "In4.Cu")
		(net "M_C_CPU0_SA_CS_N<3>")
	)
	(segment
		(start 341.364316 -259.616702)
		(end 341.364062 -259.616956)
		(width 0.20066)
		(layer "F.Cu")
		(net "M_C_CPU0_SA_CS_N<2>")
	)
	(segment
		(start 341.364316 -259.081016)
		(end 341.364316 -259.616702)
		(width 0.20066)
		(layer "F.Cu")
		(net "M_C_CPU0_SA_CS_N<2>")
	)
	(segment
		(start 279.816814 -267.866622)
		(end 278.711914 -267.866622)
		(width 0.20066)
		(layer "F.Cu")
		(net "M_C_CPU0_SA_CS_N<2>")
	)
	(segment
		(start 331.127608 -258.85394)
		(end 325.640192 -258.85394)
		(width 0.18288)
		(layer "In4.Cu")
		(net "M_C_CPU0_SA_CS_N<2>")
	)
	(segment
		(start 282.185618 -268.291818)
		(end 280.24201 -268.291818)
		(width 0.18288)
		(layer "In4.Cu")
		(net "M_C_CPU0_SA_CS_N<2>")
	)
	(segment
		(start 310.878728 -266.914376)
		(end 310.351424 -267.44168)
		(width 0.18288)
		(layer "In4.Cu")
		(net "M_C_CPU0_SA_CS_N<2>")
	)
	(segment
		(start 338.640166 -258.80314)
		(end 338.640166 -258.788916)
		(width 0.088646)
		(layer "In4.Cu")
		(net "M_C_CPU0_SA_CS_N<2>")
	)
	(segment
		(start 312.506106 -265.544808)
		(end 311.827164 -265.544808)
		(width 0.18288)
		(layer "In4.Cu")
		(net "M_C_CPU0_SA_CS_N<2>")
	)
	(segment
		(start 317.076328 -262.401304)
		(end 314.560966 -264.916666)
		(width 0.18288)
		(layer "In4.Cu")
		(net "M_C_CPU0_SA_CS_N<2>")
	)
	(segment
		(start 287.772602 -269.14221)
		(end 283.03601 -269.14221)
		(width 0.18288)
		(layer "In4.Cu")
		(net "M_C_CPU0_SA_CS_N<2>")
	)
	(segment
		(start 325.640192 -258.85394)
		(end 317.076328 -262.401304)
		(width 0.18288)
		(layer "In4.Cu")
		(net "M_C_CPU0_SA_CS_N<2>")
	)
	(segment
		(start 331.935328 -258.04622)
		(end 331.127608 -258.85394)
		(width 0.18288)
		(layer "In4.Cu")
		(net "M_C_CPU0_SA_CS_N<2>")
	)
	(segment
		(start 283.03601 -269.14221)
		(end 282.185618 -268.291818)
		(width 0.18288)
		(layer "In4.Cu")
		(net "M_C_CPU0_SA_CS_N<2>")
	)
	(segment
		(start 314.560966 -264.916666)
		(end 313.134248 -264.916666)
		(width 0.18288)
		(layer "In4.Cu")
		(net "M_C_CPU0_SA_CS_N<2>")
	)
	(segment
		(start 340.156546 -259.118862)
		(end 340.141814 -259.127498)
		(width 0.088646)
		(layer "In4.Cu")
		(net "M_C_CPU0_SA_CS_N<2>")
	)
	(segment
		(start 294.092376 -267.442188)
		(end 293.066724 -267.442188)
		(width 0.18288)
		(layer "In4.Cu")
		(net "M_C_CPU0_SA_CS_N<2>")
	)
	(segment
		(start 294.092884 -267.44168)
		(end 294.092376 -267.442188)
		(width 0.18288)
		(layer "In4.Cu")
		(net "M_C_CPU0_SA_CS_N<2>")
	)
	(segment
		(start 341.051388 -259.616956)
		(end 340.985856 -259.551424)
		(width 0.088646)
		(layer "In4.Cu")
		(net "M_C_CPU0_SA_CS_N<2>")
	)
	(segment
		(start 333.375762 -258.237736)
		(end 333.234792 -258.237736)
		(width 0.088646)
		(layer "In4.Cu")
		(net "M_C_CPU0_SA_CS_N<2>")
	)
	(segment
		(start 288.52368 -268.391132)
		(end 287.772602 -269.14221)
		(width 0.18288)
		(layer "In4.Cu")
		(net "M_C_CPU0_SA_CS_N<2>")
	)
	(segment
		(start 332.375002 -258.04622)
		(end 331.935328 -258.04622)
		(width 0.18288)
		(layer "In4.Cu")
		(net "M_C_CPU0_SA_CS_N<2>")
	)
	(segment
		(start 313.134248 -264.916666)
		(end 312.506106 -265.544808)
		(width 0.18288)
		(layer "In4.Cu")
		(net "M_C_CPU0_SA_CS_N<2>")
	)
	(segment
		(start 280.24201 -268.291818)
		(end 279.816814 -267.866622)
		(width 0.18288)
		(layer "In4.Cu")
		(net "M_C_CPU0_SA_CS_N<2>")
	)
	(segment
		(start 310.351424 -267.44168)
		(end 294.092884 -267.44168)
		(width 0.18288)
		(layer "In4.Cu")
		(net "M_C_CPU0_SA_CS_N<2>")
	)
	(segment
		(start 338.827618 -259.127498)
		(end 338.818728 -259.122418)
		(width 0.088646)
		(layer "In4.Cu")
		(net "M_C_CPU0_SA_CS_N<2>")
	)
	(segment
		(start 293.066724 -267.442188)
		(end 292.11778 -268.391132)
		(width 0.18288)
		(layer "In4.Cu")
		(net "M_C_CPU0_SA_CS_N<2>")
	)
	(segment
		(start 333.234792 -258.237736)
		(end 333.043276 -258.04622)
		(width 0.088646)
		(layer "In4.Cu")
		(net "M_C_CPU0_SA_CS_N<2>")
	)
	(segment
		(start 333.043276 -258.04622)
		(end 332.375002 -258.04622)
		(width 0.088646)
		(layer "In4.Cu")
		(net "M_C_CPU0_SA_CS_N<2>")
	)
	(segment
		(start 311.827164 -265.544808)
		(end 310.878728 -266.493244)
		(width 0.18288)
		(layer "In4.Cu")
		(net "M_C_CPU0_SA_CS_N<2>")
	)
	(segment
		(start 292.11778 -268.391132)
		(end 288.52368 -268.391132)
		(width 0.18288)
		(layer "In4.Cu")
		(net "M_C_CPU0_SA_CS_N<2>")
	)
	(segment
		(start 337.802474 -258.307332)
		(end 337.79206 -258.313428)
		(width 0.088646)
		(layer "In4.Cu")
		(net "M_C_CPU0_SA_CS_N<2>")
	)
	(segment
		(start 310.878728 -266.493244)
		(end 310.878728 -266.914376)
		(width 0.18288)
		(layer "In4.Cu")
		(net "M_C_CPU0_SA_CS_N<2>")
	)
	(segment
		(start 341.364062 -259.616956)
		(end 341.051388 -259.616956)
		(width 0.088646)
		(layer "In4.Cu")
		(net "M_C_CPU0_SA_CS_N<2>")
	)
	(arc
		(start 334.598264 -258.313428)
		(mid 334.315562 -258.237686)
		(end 334.03286 -258.313428)
		(width 0.088646)
		(layer "In4.Cu")
		(net "M_C_CPU0_SA_CS_N<2>")
	)
	(arc
		(start 335.538064 -258.313428)
		(mid 335.255362 -258.237686)
		(end 334.97266 -258.313428)
		(width 0.088646)
		(layer "In4.Cu")
		(net "M_C_CPU0_SA_CS_N<2>")
	)
	(arc
		(start 340.707218 -259.127498)
		(mid 340.433019 -259.051663)
		(end 340.156546 -259.118862)
		(width 0.088646)
		(layer "In4.Cu")
		(net "M_C_CPU0_SA_CS_N<2>")
	)
	(arc
		(start 339.202014 -259.127498)
		(mid 339.014816 -259.177641)
		(end 338.827618 -259.127498)
		(width 0.088646)
		(layer "In4.Cu")
		(net "M_C_CPU0_SA_CS_N<2>")
	)
	(arc
		(start 338.818728 -259.122418)
		(mid 338.687814 -258.986058)
		(end 338.640166 -258.80314)
		(width 0.088646)
		(layer "In4.Cu")
		(net "M_C_CPU0_SA_CS_N<2>")
	)
	(arc
		(start 334.97266 -258.313428)
		(mid 334.785462 -258.363571)
		(end 334.598264 -258.313428)
		(width 0.088646)
		(layer "In4.Cu")
		(net "M_C_CPU0_SA_CS_N<2>")
	)
	(arc
		(start 337.417664 -258.313428)
		(mid 337.134962 -258.237686)
		(end 336.85226 -258.313428)
		(width 0.088646)
		(layer "In4.Cu")
		(net "M_C_CPU0_SA_CS_N<2>")
	)
	(arc
		(start 340.985856 -259.551424)
		(mid 340.896768 -259.306439)
		(end 340.707218 -259.127498)
		(width 0.088646)
		(layer "In4.Cu")
		(net "M_C_CPU0_SA_CS_N<2>")
	)
	(arc
		(start 338.357718 -258.313428)
		(mid 338.080905 -258.237592)
		(end 337.802474 -258.307332)
		(width 0.088646)
		(layer "In4.Cu")
		(net "M_C_CPU0_SA_CS_N<2>")
	)
	(arc
		(start 336.477864 -258.313428)
		(mid 336.195162 -258.237686)
		(end 335.91246 -258.313428)
		(width 0.088646)
		(layer "In4.Cu")
		(net "M_C_CPU0_SA_CS_N<2>")
	)
	(arc
		(start 338.640166 -258.788916)
		(mid 338.561025 -258.514293)
		(end 338.357718 -258.313428)
		(width 0.088646)
		(layer "In4.Cu")
		(net "M_C_CPU0_SA_CS_N<2>")
	)
	(arc
		(start 333.658464 -258.313428)
		(mid 333.522098 -258.25695)
		(end 333.375762 -258.237736)
		(width 0.088646)
		(layer "In4.Cu")
		(net "M_C_CPU0_SA_CS_N<2>")
	)
	(arc
		(start 340.141814 -259.127498)
		(mid 339.954616 -259.177641)
		(end 339.767418 -259.127498)
		(width 0.088646)
		(layer "In4.Cu")
		(net "M_C_CPU0_SA_CS_N<2>")
	)
	(arc
		(start 334.03286 -258.313428)
		(mid 333.845662 -258.363571)
		(end 333.658464 -258.313428)
		(width 0.088646)
		(layer "In4.Cu")
		(net "M_C_CPU0_SA_CS_N<2>")
	)
	(arc
		(start 335.91246 -258.313428)
		(mid 335.725262 -258.363571)
		(end 335.538064 -258.313428)
		(width 0.088646)
		(layer "In4.Cu")
		(net "M_C_CPU0_SA_CS_N<2>")
	)
	(arc
		(start 337.79206 -258.313428)
		(mid 337.604862 -258.363571)
		(end 337.417664 -258.313428)
		(width 0.088646)
		(layer "In4.Cu")
		(net "M_C_CPU0_SA_CS_N<2>")
	)
	(arc
		(start 336.85226 -258.313428)
		(mid 336.665062 -258.363571)
		(end 336.477864 -258.313428)
		(width 0.088646)
		(layer "In4.Cu")
		(net "M_C_CPU0_SA_CS_N<2>")
	)
	(arc
		(start 339.767418 -259.127498)
		(mid 339.484716 -259.051722)
		(end 339.202014 -259.127498)
		(width 0.088646)
		(layer "In4.Cu")
		(net "M_C_CPU0_SA_CS_N<2>")
	)
	(segment
		(start 339.954616 -258.267454)
		(end 339.954616 -258.80314)
		(width 0.20066)
		(layer "F.Cu")
		(net "M_C_CPU0_SA_CS_N<1>")
	)
	(segment
		(start 276.373082 -267.016738)
		(end 275.268182 -267.016738)
		(width 0.20066)
		(layer "F.Cu")
		(net "M_C_CPU0_SA_CS_N<1>")
	)
	(segment
		(start 339.954362 -258.2672)
		(end 339.954616 -258.267454)
		(width 0.20066)
		(layer "F.Cu")
		(net "M_C_CPU0_SA_CS_N<1>")
	)
	(segment
		(start 325.087996 -258.51866)
		(end 316.537848 -262.060944)
		(width 0.18288)
		(layer "In4.Cu")
		(net "M_C_CPU0_SA_CS_N<1>")
	)
	(segment
		(start 311.580784 -264.998962)
		(end 309.98795 -266.591796)
		(width 0.18288)
		(layer "In4.Cu")
		(net "M_C_CPU0_SA_CS_N<1>")
	)
	(segment
		(start 333.375762 -257.740404)
		(end 332.843124 -257.740404)
		(width 0.088646)
		(layer "In4.Cu")
		(net "M_C_CPU0_SA_CS_N<1>")
	)
	(segment
		(start 339.44306 -258.61772)
		(end 339.202014 -258.478782)
		(width 0.088646)
		(layer "In4.Cu")
		(net "M_C_CPU0_SA_CS_N<1>")
	)
	(segment
		(start 313.250834 -263.961626)
		(end 312.213498 -264.998962)
		(width 0.18288)
		(layer "In4.Cu")
		(net "M_C_CPU0_SA_CS_N<1>")
	)
	(segment
		(start 308.203854 -266.591796)
		(end 292.502082 -266.591796)
		(width 0.18288)
		(layer "In4.Cu")
		(net "M_C_CPU0_SA_CS_N<1>")
	)
	(segment
		(start 309.077614 -266.408916)
		(end 309.077614 -265.482832)
		(width 0.18288)
		(layer "In4.Cu")
		(net "M_C_CPU0_SA_CS_N<1>")
	)
	(segment
		(start 332.843124 -257.740404)
		(end 332.81366 -257.71094)
		(width 0.088646)
		(layer "In4.Cu")
		(net "M_C_CPU0_SA_CS_N<1>")
	)
	(segment
		(start 330.945236 -258.51866)
		(end 325.087996 -258.51866)
		(width 0.18288)
		(layer "In4.Cu")
		(net "M_C_CPU0_SA_CS_N<1>")
	)
	(segment
		(start 332.37551 -257.71094)
		(end 331.752956 -257.71094)
		(width 0.18288)
		(layer "In4.Cu")
		(net "M_C_CPU0_SA_CS_N<1>")
	)
	(segment
		(start 276.794976 -266.594844)
		(end 276.373082 -267.016738)
		(width 0.18288)
		(layer "In4.Cu")
		(net "M_C_CPU0_SA_CS_N<1>")
	)
	(segment
		(start 287.77311 -268.291818)
		(end 283.034232 -268.291818)
		(width 0.18288)
		(layer "In4.Cu")
		(net "M_C_CPU0_SA_CS_N<1>")
	)
	(segment
		(start 308.894734 -265.299952)
		(end 308.569614 -265.299952)
		(width 0.18288)
		(layer "In4.Cu")
		(net "M_C_CPU0_SA_CS_N<1>")
	)
	(segment
		(start 309.98795 -266.591796)
		(end 309.260494 -266.591796)
		(width 0.18288)
		(layer "In4.Cu")
		(net "M_C_CPU0_SA_CS_N<1>")
	)
	(segment
		(start 337.802474 -257.670808)
		(end 337.79206 -257.664712)
		(width 0.088646)
		(layer "In4.Cu")
		(net "M_C_CPU0_SA_CS_N<1>")
	)
	(segment
		(start 308.386734 -265.482832)
		(end 308.386734 -266.408916)
		(width 0.18288)
		(layer "In4.Cu")
		(net "M_C_CPU0_SA_CS_N<1>")
	)
	(segment
		(start 281.759152 -267.016738)
		(end 280.868882 -267.016738)
		(width 0.18288)
		(layer "In4.Cu")
		(net "M_C_CPU0_SA_CS_N<1>")
	)
	(segment
		(start 280.868882 -267.016738)
		(end 280.446988 -266.594844)
		(width 0.18288)
		(layer "In4.Cu")
		(net "M_C_CPU0_SA_CS_N<1>")
	)
	(segment
		(start 283.034232 -268.291818)
		(end 281.759152 -267.016738)
		(width 0.18288)
		(layer "In4.Cu")
		(net "M_C_CPU0_SA_CS_N<1>")
	)
	(segment
		(start 339.954616 -258.80314)
		(end 339.946742 -258.795266)
		(width 0.088646)
		(layer "In4.Cu")
		(net "M_C_CPU0_SA_CS_N<1>")
	)
	(segment
		(start 316.537848 -262.060944)
		(end 314.637166 -263.961626)
		(width 0.18288)
		(layer "In4.Cu")
		(net "M_C_CPU0_SA_CS_N<1>")
	)
	(segment
		(start 332.81366 -257.71094)
		(end 332.37551 -257.71094)
		(width 0.088646)
		(layer "In4.Cu")
		(net "M_C_CPU0_SA_CS_N<1>")
	)
	(segment
		(start 280.446988 -266.594844)
		(end 276.794976 -266.594844)
		(width 0.18288)
		(layer "In4.Cu")
		(net "M_C_CPU0_SA_CS_N<1>")
	)
	(segment
		(start 331.752956 -257.71094)
		(end 330.945236 -258.51866)
		(width 0.18288)
		(layer "In4.Cu")
		(net "M_C_CPU0_SA_CS_N<1>")
	)
	(segment
		(start 308.569614 -265.299952)
		(end 308.386734 -265.482832)
		(width 0.18288)
		(layer "In4.Cu")
		(net "M_C_CPU0_SA_CS_N<1>")
	)
	(segment
		(start 292.502082 -266.591796)
		(end 291.65042 -267.443458)
		(width 0.18288)
		(layer "In4.Cu")
		(net "M_C_CPU0_SA_CS_N<1>")
	)
	(segment
		(start 314.637166 -263.961626)
		(end 313.250834 -263.961626)
		(width 0.18288)
		(layer "In4.Cu")
		(net "M_C_CPU0_SA_CS_N<1>")
	)
	(segment
		(start 291.65042 -267.443458)
		(end 288.62147 -267.443458)
		(width 0.18288)
		(layer "In4.Cu")
		(net "M_C_CPU0_SA_CS_N<1>")
	)
	(segment
		(start 288.62147 -267.443458)
		(end 287.77311 -268.291818)
		(width 0.18288)
		(layer "In4.Cu")
		(net "M_C_CPU0_SA_CS_N<1>")
	)
	(segment
		(start 309.260494 -266.591796)
		(end 309.077614 -266.408916)
		(width 0.18288)
		(layer "In4.Cu")
		(net "M_C_CPU0_SA_CS_N<1>")
	)
	(segment
		(start 312.213498 -264.998962)
		(end 311.580784 -264.998962)
		(width 0.18288)
		(layer "In4.Cu")
		(net "M_C_CPU0_SA_CS_N<1>")
	)
	(segment
		(start 338.919312 -258.003294)
		(end 338.919312 -257.980434)
		(width 0.088646)
		(layer "In4.Cu")
		(net "M_C_CPU0_SA_CS_N<1>")
	)
	(segment
		(start 308.386734 -266.408916)
		(end 308.203854 -266.591796)
		(width 0.18288)
		(layer "In4.Cu")
		(net "M_C_CPU0_SA_CS_N<1>")
	)
	(segment
		(start 309.077614 -265.482832)
		(end 308.894734 -265.299952)
		(width 0.18288)
		(layer "In4.Cu")
		(net "M_C_CPU0_SA_CS_N<1>")
	)
	(arc
		(start 337.417664 -257.664712)
		(mid 337.134962 -257.740488)
		(end 336.85226 -257.664712)
		(width 0.088646)
		(layer "In4.Cu")
		(net "M_C_CPU0_SA_CS_N<1>")
	)
	(arc
		(start 339.656166 -258.67487)
		(mid 339.545863 -258.660291)
		(end 339.44306 -258.61772)
		(width 0.088646)
		(layer "In4.Cu")
		(net "M_C_CPU0_SA_CS_N<1>")
	)
	(arc
		(start 339.202014 -258.478782)
		(mid 338.998533 -258.277978)
		(end 338.919312 -258.003294)
		(width 0.088646)
		(layer "In4.Cu")
		(net "M_C_CPU0_SA_CS_N<1>")
	)
	(arc
		(start 333.658464 -257.664712)
		(mid 333.522095 -257.721154)
		(end 333.375762 -257.740404)
		(width 0.088646)
		(layer "In4.Cu")
		(net "M_C_CPU0_SA_CS_N<1>")
	)
	(arc
		(start 335.91246 -257.664712)
		(mid 335.725262 -257.614569)
		(end 335.538064 -257.664712)
		(width 0.088646)
		(layer "In4.Cu")
		(net "M_C_CPU0_SA_CS_N<1>")
	)
	(arc
		(start 334.03286 -257.664712)
		(mid 333.845662 -257.614569)
		(end 333.658464 -257.664712)
		(width 0.088646)
		(layer "In4.Cu")
		(net "M_C_CPU0_SA_CS_N<1>")
	)
	(arc
		(start 338.919312 -257.980434)
		(mid 338.867042 -257.798069)
		(end 338.732114 -257.664712)
		(width 0.088646)
		(layer "In4.Cu")
		(net "M_C_CPU0_SA_CS_N<1>")
	)
	(arc
		(start 336.85226 -257.664712)
		(mid 336.665062 -257.614569)
		(end 336.477864 -257.664712)
		(width 0.088646)
		(layer "In4.Cu")
		(net "M_C_CPU0_SA_CS_N<1>")
	)
	(arc
		(start 334.97266 -257.664712)
		(mid 334.785462 -257.614569)
		(end 334.598264 -257.664712)
		(width 0.088646)
		(layer "In4.Cu")
		(net "M_C_CPU0_SA_CS_N<1>")
	)
	(arc
		(start 334.598264 -257.664712)
		(mid 334.315562 -257.740488)
		(end 334.03286 -257.664712)
		(width 0.088646)
		(layer "In4.Cu")
		(net "M_C_CPU0_SA_CS_N<1>")
	)
	(arc
		(start 339.946742 -258.795266)
		(mid 339.813425 -258.706186)
		(end 339.656166 -258.67487)
		(width 0.088646)
		(layer "In4.Cu")
		(net "M_C_CPU0_SA_CS_N<1>")
	)
	(arc
		(start 336.477864 -257.664712)
		(mid 336.195162 -257.740488)
		(end 335.91246 -257.664712)
		(width 0.088646)
		(layer "In4.Cu")
		(net "M_C_CPU0_SA_CS_N<1>")
	)
	(arc
		(start 338.732114 -257.664712)
		(mid 338.544916 -257.614569)
		(end 338.357718 -257.664712)
		(width 0.088646)
		(layer "In4.Cu")
		(net "M_C_CPU0_SA_CS_N<1>")
	)
	(arc
		(start 337.79206 -257.664712)
		(mid 337.604862 -257.614569)
		(end 337.417664 -257.664712)
		(width 0.088646)
		(layer "In4.Cu")
		(net "M_C_CPU0_SA_CS_N<1>")
	)
	(arc
		(start 335.538064 -257.664712)
		(mid 335.255362 -257.740488)
		(end 334.97266 -257.664712)
		(width 0.088646)
		(layer "In4.Cu")
		(net "M_C_CPU0_SA_CS_N<1>")
	)
	(arc
		(start 338.357718 -257.664712)
		(mid 338.080905 -257.740582)
		(end 337.802474 -257.670808)
		(width 0.088646)
		(layer "In4.Cu")
		(net "M_C_CPU0_SA_CS_N<1>")
	)
	(segment
		(start 340.424516 -259.081016)
		(end 340.424516 -259.616702)
		(width 0.20066)
		(layer "F.Cu")
		(net "M_C_CPU0_SA_CS_N<0>")
	)
	(segment
		(start 340.424516 -259.616702)
		(end 340.424262 -259.616956)
		(width 0.20066)
		(layer "F.Cu")
		(net "M_C_CPU0_SA_CS_N<0>")
	)
	(segment
		(start 272.273014 -267.866622)
		(end 271.168114 -267.866622)
		(width 0.20066)
		(layer "F.Cu")
		(net "M_C_CPU0_SA_CS_N<0>")
	)
	(segment
		(start 338.27085 -258.483862)
		(end 338.26196 -258.478782)
		(width 0.088646)
		(layer "In4.Cu")
		(net "M_C_CPU0_SA_CS_N<0>")
	)
	(segment
		(start 333.004414 -258.3815)
		(end 332.375002 -258.3815)
		(width 0.088646)
		(layer "In4.Cu")
		(net "M_C_CPU0_SA_CS_N<0>")
	)
	(segment
		(start 332.375002 -258.3815)
		(end 332.098396 -258.3815)
		(width 0.18288)
		(layer "In4.Cu")
		(net "M_C_CPU0_SA_CS_N<0>")
	)
	(segment
		(start 282.999942 -269.993618)
		(end 282.148026 -269.141702)
		(width 0.18288)
		(layer "In4.Cu")
		(net "M_C_CPU0_SA_CS_N<0>")
	)
	(segment
		(start 331.290676 -259.18922)
		(end 326.200262 -259.18922)
		(width 0.18288)
		(layer "In4.Cu")
		(net "M_C_CPU0_SA_CS_N<0>")
	)
	(segment
		(start 326.200262 -259.18922)
		(end 317.474854 -262.804656)
		(width 0.18288)
		(layer "In4.Cu")
		(net "M_C_CPU0_SA_CS_N<0>")
	)
	(segment
		(start 317.474854 -262.804656)
		(end 314.659518 -265.619992)
		(width 0.18288)
		(layer "In4.Cu")
		(net "M_C_CPU0_SA_CS_N<0>")
	)
	(segment
		(start 332.098396 -258.3815)
		(end 331.290676 -259.18922)
		(width 0.18288)
		(layer "In4.Cu")
		(net "M_C_CPU0_SA_CS_N<0>")
	)
	(segment
		(start 282.148026 -269.141702)
		(end 273.548094 -269.141702)
		(width 0.18288)
		(layer "In4.Cu")
		(net "M_C_CPU0_SA_CS_N<0>")
	)
	(segment
		(start 292.070536 -269.246858)
		(end 291.822632 -268.998954)
		(width 0.18288)
		(layer "In4.Cu")
		(net "M_C_CPU0_SA_CS_N<0>")
	)
	(segment
		(start 333.050896 -258.427982)
		(end 333.004414 -258.3815)
		(width 0.088646)
		(layer "In4.Cu")
		(net "M_C_CPU0_SA_CS_N<0>")
	)
	(segment
		(start 340.424262 -259.616956)
		(end 340.736936 -259.616956)
		(width 0.088646)
		(layer "In4.Cu")
		(net "M_C_CPU0_SA_CS_N<0>")
	)
	(segment
		(start 291.822632 -268.998954)
		(end 288.88309 -268.998954)
		(width 0.18288)
		(layer "In4.Cu")
		(net "M_C_CPU0_SA_CS_N<0>")
	)
	(segment
		(start 313.264804 -265.619992)
		(end 310.592978 -268.291818)
		(width 0.18288)
		(layer "In4.Cu")
		(net "M_C_CPU0_SA_CS_N<0>")
	)
	(segment
		(start 340.237064 -259.292598)
		(end 340.22665 -259.298694)
		(width 0.088646)
		(layer "In4.Cu")
		(net "M_C_CPU0_SA_CS_N<0>")
	)
	(segment
		(start 333.375762 -258.427982)
		(end 333.050896 -258.427982)
		(width 0.088646)
		(layer "In4.Cu")
		(net "M_C_CPU0_SA_CS_N<0>")
	)
	(segment
		(start 310.592978 -268.291818)
		(end 293.80053 -268.291818)
		(width 0.18288)
		(layer "In4.Cu")
		(net "M_C_CPU0_SA_CS_N<0>")
	)
	(segment
		(start 288.88309 -268.998954)
		(end 287.888426 -269.993618)
		(width 0.18288)
		(layer "In4.Cu")
		(net "M_C_CPU0_SA_CS_N<0>")
	)
	(segment
		(start 340.62035 -259.297678)
		(end 340.61146 -259.292598)
		(width 0.088646)
		(layer "In4.Cu")
		(net "M_C_CPU0_SA_CS_N<0>")
	)
	(segment
		(start 314.659518 -265.619992)
		(end 313.264804 -265.619992)
		(width 0.18288)
		(layer "In4.Cu")
		(net "M_C_CPU0_SA_CS_N<0>")
	)
	(segment
		(start 339.297518 -259.292598)
		(end 339.287104 -259.298694)
		(width 0.088646)
		(layer "In4.Cu")
		(net "M_C_CPU0_SA_CS_N<0>")
	)
	(segment
		(start 287.888426 -269.993618)
		(end 282.999942 -269.993618)
		(width 0.18288)
		(layer "In4.Cu")
		(net "M_C_CPU0_SA_CS_N<0>")
	)
	(segment
		(start 293.80053 -268.291818)
		(end 292.84549 -269.246858)
		(width 0.18288)
		(layer "In4.Cu")
		(net "M_C_CPU0_SA_CS_N<0>")
	)
	(segment
		(start 338.73186 -259.292598)
		(end 338.725764 -259.289042)
		(width 0.088646)
		(layer "In4.Cu")
		(net "M_C_CPU0_SA_CS_N<0>")
	)
	(segment
		(start 292.84549 -269.246858)
		(end 292.070536 -269.246858)
		(width 0.18288)
		(layer "In4.Cu")
		(net "M_C_CPU0_SA_CS_N<0>")
	)
	(segment
		(start 340.736936 -259.616956)
		(end 340.79434 -259.559552)
		(width 0.088646)
		(layer "In4.Cu")
		(net "M_C_CPU0_SA_CS_N<0>")
	)
	(segment
		(start 273.548094 -269.141702)
		(end 272.273014 -267.866622)
		(width 0.18288)
		(layer "In4.Cu")
		(net "M_C_CPU0_SA_CS_N<0>")
	)
	(arc
		(start 334.50276 -258.478782)
		(mid 334.315562 -258.428639)
		(end 334.128364 -258.478782)
		(width 0.088646)
		(layer "In4.Cu")
		(net "M_C_CPU0_SA_CS_N<0>")
	)
	(arc
		(start 340.22665 -259.298694)
		(mid 339.948472 -259.368417)
		(end 339.671914 -259.292598)
		(width 0.088646)
		(layer "In4.Cu")
		(net "M_C_CPU0_SA_CS_N<0>")
	)
	(arc
		(start 338.449412 -258.80314)
		(mid 338.401733 -258.62024)
		(end 338.27085 -258.483862)
		(width 0.088646)
		(layer "In4.Cu")
		(net "M_C_CPU0_SA_CS_N<0>")
	)
	(arc
		(start 339.287104 -259.298694)
		(mid 339.008672 -259.36854)
		(end 338.73186 -259.292598)
		(width 0.088646)
		(layer "In4.Cu")
		(net "M_C_CPU0_SA_CS_N<0>")
	)
	(arc
		(start 337.887564 -258.478782)
		(mid 337.604862 -258.554524)
		(end 337.32216 -258.478782)
		(width 0.088646)
		(layer "In4.Cu")
		(net "M_C_CPU0_SA_CS_N<0>")
	)
	(arc
		(start 340.79434 -259.559552)
		(mid 340.736184 -259.409439)
		(end 340.62035 -259.297678)
		(width 0.088646)
		(layer "In4.Cu")
		(net "M_C_CPU0_SA_CS_N<0>")
	)
	(arc
		(start 333.56296 -258.478782)
		(mid 333.472704 -258.44106)
		(end 333.375762 -258.427982)
		(width 0.088646)
		(layer "In4.Cu")
		(net "M_C_CPU0_SA_CS_N<0>")
	)
	(arc
		(start 335.44256 -258.478782)
		(mid 335.255362 -258.428639)
		(end 335.068164 -258.478782)
		(width 0.088646)
		(layer "In4.Cu")
		(net "M_C_CPU0_SA_CS_N<0>")
	)
	(arc
		(start 334.128364 -258.478782)
		(mid 333.845662 -258.554524)
		(end 333.56296 -258.478782)
		(width 0.088646)
		(layer "In4.Cu")
		(net "M_C_CPU0_SA_CS_N<0>")
	)
	(arc
		(start 335.068164 -258.478782)
		(mid 334.785462 -258.554524)
		(end 334.50276 -258.478782)
		(width 0.088646)
		(layer "In4.Cu")
		(net "M_C_CPU0_SA_CS_N<0>")
	)
	(arc
		(start 340.61146 -259.292598)
		(mid 340.424262 -259.242455)
		(end 340.237064 -259.292598)
		(width 0.088646)
		(layer "In4.Cu")
		(net "M_C_CPU0_SA_CS_N<0>")
	)
	(arc
		(start 336.38236 -258.478782)
		(mid 336.195162 -258.428639)
		(end 336.007964 -258.478782)
		(width 0.088646)
		(layer "In4.Cu")
		(net "M_C_CPU0_SA_CS_N<0>")
	)
	(arc
		(start 337.32216 -258.478782)
		(mid 337.134962 -258.428639)
		(end 336.947764 -258.478782)
		(width 0.088646)
		(layer "In4.Cu")
		(net "M_C_CPU0_SA_CS_N<0>")
	)
	(arc
		(start 336.947764 -258.478782)
		(mid 336.665062 -258.554524)
		(end 336.38236 -258.478782)
		(width 0.088646)
		(layer "In4.Cu")
		(net "M_C_CPU0_SA_CS_N<0>")
	)
	(arc
		(start 338.725764 -259.289042)
		(mid 338.523351 -259.082629)
		(end 338.449412 -258.80314)
		(width 0.088646)
		(layer "In4.Cu")
		(net "M_C_CPU0_SA_CS_N<0>")
	)
	(arc
		(start 339.671914 -259.292598)
		(mid 339.484716 -259.242455)
		(end 339.297518 -259.292598)
		(width 0.088646)
		(layer "In4.Cu")
		(net "M_C_CPU0_SA_CS_N<0>")
	)
	(arc
		(start 336.007964 -258.478782)
		(mid 335.725262 -258.554524)
		(end 335.44256 -258.478782)
		(width 0.088646)
		(layer "In4.Cu")
		(net "M_C_CPU0_SA_CS_N<0>")
	)
	(arc
		(start 338.26196 -258.478782)
		(mid 338.074762 -258.428639)
		(end 337.887564 -258.478782)
		(width 0.088646)
		(layer "In4.Cu")
		(net "M_C_CPU0_SA_CS_N<0>")
	)
	(segment
		(start 283.916882 -270.416782)
		(end 282.811982 -270.416782)
		(width 0.20066)
		(layer "F.Cu")
		(net "M_C_CPU0_SA_CB<7>")
	)
	(segment
		(start 344.653362 -258.2672)
		(end 344.653362 -258.802886)
		(width 0.20066)
		(layer "F.Cu")
		(net "M_C_CPU0_SA_CB<7>")
	)
	(segment
		(start 279.96896 -270.841724)
		(end 279.912826 -270.841724)
		(width 0.101854)
		(layer "F.Cu")
		(net "M_C_CPU0_SA_CB<7>")
	)
	(segment
		(start 280.606246 -270.641064)
		(end 280.405586 -270.841724)
		(width 0.20066)
		(layer "F.Cu")
		(net "M_C_CPU0_SA_CB<7>")
	)
	(segment
		(start 280.806906 -270.278098)
		(end 280.606246 -270.478758)
		(width 0.20066)
		(layer "F.Cu")
		(net "M_C_CPU0_SA_CB<7>")
	)
	(segment
		(start 277.091394 -270.542766)
		(end 276.96541 -270.416782)
		(width 0.20066)
		(layer "F.Cu")
		(net "M_C_CPU0_SA_CB<7>")
	)
	(segment
		(start 277.091394 -270.69923)
		(end 277.091394 -270.542766)
		(width 0.20066)
		(layer "F.Cu")
		(net "M_C_CPU0_SA_CB<7>")
	)
	(segment
		(start 281.99588 -270.416782)
		(end 281.890216 -270.522446)
		(width 0.20066)
		(layer "F.Cu")
		(net "M_C_CPU0_SA_CB<7>")
	)
	(segment
		(start 280.606246 -270.478758)
		(end 280.606246 -270.641064)
		(width 0.20066)
		(layer "F.Cu")
		(net "M_C_CPU0_SA_CB<7>")
	)
	(segment
		(start 277.456392 -270.841724)
		(end 277.233888 -270.841724)
		(width 0.20066)
		(layer "F.Cu")
		(net "M_C_CPU0_SA_CB<7>")
	)
	(segment
		(start 280.405586 -270.841724)
		(end 279.96896 -270.841724)
		(width 0.20066)
		(layer "F.Cu")
		(net "M_C_CPU0_SA_CB<7>")
	)
	(segment
		(start 282.811982 -270.416782)
		(end 281.99588 -270.416782)
		(width 0.20066)
		(layer "F.Cu")
		(net "M_C_CPU0_SA_CB<7>")
	)
	(segment
		(start 281.362912 -270.522446)
		(end 281.118564 -270.278098)
		(width 0.20066)
		(layer "F.Cu")
		(net "M_C_CPU0_SA_CB<7>")
	)
	(segment
		(start 277.233888 -270.841724)
		(end 277.091394 -270.69923)
		(width 0.20066)
		(layer "F.Cu")
		(net "M_C_CPU0_SA_CB<7>")
	)
	(segment
		(start 281.118564 -270.278098)
		(end 280.806906 -270.278098)
		(width 0.20066)
		(layer "F.Cu")
		(net "M_C_CPU0_SA_CB<7>")
	)
	(segment
		(start 344.653362 -258.802886)
		(end 344.653616 -258.80314)
		(width 0.20066)
		(layer "F.Cu")
		(net "M_C_CPU0_SA_CB<7>")
	)
	(segment
		(start 277.601934 -270.841724)
		(end 277.456392 -270.841724)
		(width 0.101854)
		(layer "F.Cu")
		(net "M_C_CPU0_SA_CB<7>")
	)
	(segment
		(start 276.96541 -270.416782)
		(end 275.268182 -270.416782)
		(width 0.20066)
		(layer "F.Cu")
		(net "M_C_CPU0_SA_CB<7>")
	)
	(segment
		(start 279.912826 -270.841724)
		(end 277.601934 -270.841724)
		(width 0.1016)
		(layer "F.Cu")
		(net "M_C_CPU0_SA_CB<7>")
	)
	(segment
		(start 281.890216 -270.522446)
		(end 281.362912 -270.522446)
		(width 0.20066)
		(layer "F.Cu")
		(net "M_C_CPU0_SA_CB<7>")
	)
	(segment
		(start 301.467774 -262.67156)
		(end 301.467774 -263.00811)
		(width 0.18288)
		(layer "In6.Cu")
		(net "M_C_CPU0_SA_CB<7>")
	)
	(segment
		(start 300.776894 -263.00811)
		(end 300.776894 -262.67156)
		(width 0.18288)
		(layer "In6.Cu")
		(net "M_C_CPU0_SA_CB<7>")
	)
	(segment
		(start 291.049202 -265.079226)
		(end 289.282378 -266.84605)
		(width 0.18288)
		(layer "In6.Cu")
		(net "M_C_CPU0_SA_CB<7>")
	)
	(segment
		(start 300.268894 -262.48868)
		(end 300.086014 -262.67156)
		(width 0.18288)
		(layer "In6.Cu")
		(net "M_C_CPU0_SA_CB<7>")
	)
	(segment
		(start 307.46065 -263.008872)
		(end 307.30063 -262.848852)
		(width 0.18288)
		(layer "In6.Cu")
		(net "M_C_CPU0_SA_CB<7>")
	)
	(segment
		(start 311.700672 -260.54304)
		(end 310.87568 -261.368032)
		(width 0.18288)
		(layer "In6.Cu")
		(net "M_C_CPU0_SA_CB<7>")
	)
	(segment
		(start 292.039294 -265.079226)
		(end 291.049202 -265.079226)
		(width 0.18288)
		(layer "In6.Cu")
		(net "M_C_CPU0_SA_CB<7>")
	)
	(segment
		(start 288.291016 -266.113006)
		(end 288.032444 -266.113006)
		(width 0.18288)
		(layer "In6.Cu")
		(net "M_C_CPU0_SA_CB<7>")
	)
	(segment
		(start 331.966062 -258.554474)
		(end 331.286358 -259.234178)
		(width 0.088646)
		(layer "In6.Cu")
		(net "M_C_CPU0_SA_CB<7>")
	)
	(segment
		(start 342.031828 -258.484878)
		(end 342.021414 -258.478782)
		(width 0.088646)
		(layer "In6.Cu")
		(net "M_C_CPU0_SA_CB<7>")
	)
	(segment
		(start 343.43086 -259.292598)
		(end 343.424764 -259.289042)
		(width 0.088646)
		(layer "In6.Cu")
		(net "M_C_CPU0_SA_CB<7>")
	)
	(segment
		(start 299.903134 -263.19099)
		(end 296.39133 -263.19099)
		(width 0.18288)
		(layer "In6.Cu")
		(net "M_C_CPU0_SA_CB<7>")
	)
	(segment
		(start 288.53511 -267.334492)
		(end 288.53511 -267.593318)
		(width 0.18288)
		(layer "In6.Cu")
		(net "M_C_CPU0_SA_CB<7>")
	)
	(segment
		(start 344.340942 -258.80314)
		(end 344.275156 -258.868926)
		(width 0.088646)
		(layer "In6.Cu")
		(net "M_C_CPU0_SA_CB<7>")
	)
	(segment
		(start 296.39133 -263.19099)
		(end 295.541446 -264.040874)
		(width 0.18288)
		(layer "In6.Cu")
		(net "M_C_CPU0_SA_CB<7>")
	)
	(segment
		(start 307.30063 -262.503666)
		(end 307.14061 -262.343646)
		(width 0.18288)
		(layer "In6.Cu")
		(net "M_C_CPU0_SA_CB<7>")
	)
	(segment
		(start 307.14061 -262.343646)
		(end 303.901602 -262.343646)
		(width 0.18288)
		(layer "In6.Cu")
		(net "M_C_CPU0_SA_CB<7>")
	)
	(segment
		(start 287.80232 -266.34313)
		(end 287.80232 -266.601702)
		(width 0.18288)
		(layer "In6.Cu")
		(net "M_C_CPU0_SA_CB<7>")
	)
	(segment
		(start 342.96985 -258.483862)
		(end 342.96096 -258.478782)
		(width 0.088646)
		(layer "In6.Cu")
		(net "M_C_CPU0_SA_CB<7>")
	)
	(segment
		(start 289.282378 -266.84605)
		(end 289.02406 -266.84605)
		(width 0.18288)
		(layer "In6.Cu")
		(net "M_C_CPU0_SA_CB<7>")
	)
	(segment
		(start 310.87568 -261.368032)
		(end 309.499 -261.368032)
		(width 0.18288)
		(layer "In6.Cu")
		(net "M_C_CPU0_SA_CB<7>")
	)
	(segment
		(start 293.077646 -264.040874)
		(end 292.039294 -265.079226)
		(width 0.18288)
		(layer "In6.Cu")
		(net "M_C_CPU0_SA_CB<7>")
	)
	(segment
		(start 300.594014 -262.48868)
		(end 300.268894 -262.48868)
		(width 0.18288)
		(layer "In6.Cu")
		(net "M_C_CPU0_SA_CB<7>")
	)
	(segment
		(start 307.30063 -262.848852)
		(end 307.30063 -262.503666)
		(width 0.18288)
		(layer "In6.Cu")
		(net "M_C_CPU0_SA_CB<7>")
	)
	(segment
		(start 331.286358 -259.234178)
		(end 331.028802 -259.234178)
		(width 0.088646)
		(layer "In6.Cu")
		(net "M_C_CPU0_SA_CB<7>")
	)
	(segment
		(start 301.284894 -263.19099)
		(end 300.959774 -263.19099)
		(width 0.18288)
		(layer "In6.Cu")
		(net "M_C_CPU0_SA_CB<7>")
	)
	(segment
		(start 287.80232 -266.601702)
		(end 288.53511 -267.334492)
		(width 0.18288)
		(layer "In6.Cu")
		(net "M_C_CPU0_SA_CB<7>")
	)
	(segment
		(start 343.996264 -259.292598)
		(end 343.981532 -259.301234)
		(width 0.088646)
		(layer "In6.Cu")
		(net "M_C_CPU0_SA_CB<7>")
	)
	(segment
		(start 341.096346 -258.487418)
		(end 341.081614 -258.478782)
		(width 0.088646)
		(layer "In6.Cu")
		(net "M_C_CPU0_SA_CB<7>")
	)
	(segment
		(start 303.901602 -262.343646)
		(end 303.054258 -263.19099)
		(width 0.18288)
		(layer "In6.Cu")
		(net "M_C_CPU0_SA_CB<7>")
	)
	(segment
		(start 301.975774 -262.48868)
		(end 301.650654 -262.48868)
		(width 0.18288)
		(layer "In6.Cu")
		(net "M_C_CPU0_SA_CB<7>")
	)
	(segment
		(start 302.341534 -263.19099)
		(end 302.158654 -263.00811)
		(width 0.18288)
		(layer "In6.Cu")
		(net "M_C_CPU0_SA_CB<7>")
	)
	(segment
		(start 301.650654 -262.48868)
		(end 301.467774 -262.67156)
		(width 0.18288)
		(layer "In6.Cu")
		(net "M_C_CPU0_SA_CB<7>")
	)
	(segment
		(start 300.086014 -263.00811)
		(end 299.903134 -263.19099)
		(width 0.18288)
		(layer "In6.Cu")
		(net "M_C_CPU0_SA_CB<7>")
	)
	(segment
		(start 287.839912 -268.288516)
		(end 287.009332 -268.288516)
		(width 0.18288)
		(layer "In6.Cu")
		(net "M_C_CPU0_SA_CB<7>")
	)
	(segment
		(start 301.467774 -263.00811)
		(end 301.284894 -263.19099)
		(width 0.18288)
		(layer "In6.Cu")
		(net "M_C_CPU0_SA_CB<7>")
	)
	(segment
		(start 325.861426 -260.54304)
		(end 311.700672 -260.54304)
		(width 0.18288)
		(layer "In6.Cu")
		(net "M_C_CPU0_SA_CB<7>")
	)
	(segment
		(start 300.086014 -262.67156)
		(end 300.086014 -263.00811)
		(width 0.18288)
		(layer "In6.Cu")
		(net "M_C_CPU0_SA_CB<7>")
	)
	(segment
		(start 331.028802 -259.234178)
		(end 329.02144 -259.234178)
		(width 0.18288)
		(layer "In6.Cu")
		(net "M_C_CPU0_SA_CB<7>")
	)
	(segment
		(start 307.99405 -262.503666)
		(end 307.99405 -262.848852)
		(width 0.18288)
		(layer "In6.Cu")
		(net "M_C_CPU0_SA_CB<7>")
	)
	(segment
		(start 289.02406 -266.84605)
		(end 288.291016 -266.113006)
		(width 0.18288)
		(layer "In6.Cu")
		(net "M_C_CPU0_SA_CB<7>")
	)
	(segment
		(start 303.054258 -263.19099)
		(end 302.341534 -263.19099)
		(width 0.18288)
		(layer "In6.Cu")
		(net "M_C_CPU0_SA_CB<7>")
	)
	(segment
		(start 285.519622 -269.778226)
		(end 284.555438 -269.778226)
		(width 0.18288)
		(layer "In6.Cu")
		(net "M_C_CPU0_SA_CB<7>")
	)
	(segment
		(start 338.827618 -258.478782)
		(end 338.817204 -258.484878)
		(width 0.088646)
		(layer "In6.Cu")
		(net "M_C_CPU0_SA_CB<7>")
	)
	(segment
		(start 287.009332 -268.288516)
		(end 285.519622 -269.778226)
		(width 0.18288)
		(layer "In6.Cu")
		(net "M_C_CPU0_SA_CB<7>")
	)
	(segment
		(start 295.541446 -264.040874)
		(end 293.077646 -264.040874)
		(width 0.18288)
		(layer "In6.Cu")
		(net "M_C_CPU0_SA_CB<7>")
	)
	(segment
		(start 302.158654 -262.67156)
		(end 301.975774 -262.48868)
		(width 0.18288)
		(layer "In6.Cu")
		(net "M_C_CPU0_SA_CB<7>")
	)
	(segment
		(start 302.158654 -263.00811)
		(end 302.158654 -262.67156)
		(width 0.18288)
		(layer "In6.Cu")
		(net "M_C_CPU0_SA_CB<7>")
	)
	(segment
		(start 308.523386 -262.343646)
		(end 308.15407 -262.343646)
		(width 0.18288)
		(layer "In6.Cu")
		(net "M_C_CPU0_SA_CB<7>")
	)
	(segment
		(start 288.032444 -266.113006)
		(end 287.80232 -266.34313)
		(width 0.18288)
		(layer "In6.Cu")
		(net "M_C_CPU0_SA_CB<7>")
	)
	(segment
		(start 307.83403 -263.008872)
		(end 307.46065 -263.008872)
		(width 0.18288)
		(layer "In6.Cu")
		(net "M_C_CPU0_SA_CB<7>")
	)
	(segment
		(start 308.15407 -262.343646)
		(end 307.99405 -262.503666)
		(width 0.18288)
		(layer "In6.Cu")
		(net "M_C_CPU0_SA_CB<7>")
	)
	(segment
		(start 307.99405 -262.848852)
		(end 307.83403 -263.008872)
		(width 0.18288)
		(layer "In6.Cu")
		(net "M_C_CPU0_SA_CB<7>")
	)
	(segment
		(start 300.776894 -262.67156)
		(end 300.594014 -262.48868)
		(width 0.18288)
		(layer "In6.Cu")
		(net "M_C_CPU0_SA_CB<7>")
	)
	(segment
		(start 344.653616 -258.80314)
		(end 344.340942 -258.80314)
		(width 0.088646)
		(layer "In6.Cu")
		(net "M_C_CPU0_SA_CB<7>")
	)
	(segment
		(start 284.555438 -269.778226)
		(end 283.916882 -270.416782)
		(width 0.18288)
		(layer "In6.Cu")
		(net "M_C_CPU0_SA_CB<7>")
	)
	(segment
		(start 329.02144 -259.234178)
		(end 325.861426 -260.54304)
		(width 0.18288)
		(layer "In6.Cu")
		(net "M_C_CPU0_SA_CB<7>")
	)
	(segment
		(start 288.53511 -267.593318)
		(end 287.839912 -268.288516)
		(width 0.18288)
		(layer "In6.Cu")
		(net "M_C_CPU0_SA_CB<7>")
	)
	(segment
		(start 300.959774 -263.19099)
		(end 300.776894 -263.00811)
		(width 0.18288)
		(layer "In6.Cu")
		(net "M_C_CPU0_SA_CB<7>")
	)
	(segment
		(start 339.216746 -258.487418)
		(end 339.202014 -258.478782)
		(width 0.088646)
		(layer "In6.Cu")
		(net "M_C_CPU0_SA_CB<7>")
	)
	(segment
		(start 344.00236 -259.289042)
		(end 343.996264 -259.292598)
		(width 0.088646)
		(layer "In6.Cu")
		(net "M_C_CPU0_SA_CB<7>")
	)
	(segment
		(start 309.499 -261.368032)
		(end 308.523386 -262.343646)
		(width 0.18288)
		(layer "In6.Cu")
		(net "M_C_CPU0_SA_CB<7>")
	)
	(arc
		(start 343.981532 -259.301234)
		(mid 343.705057 -259.368554)
		(end 343.43086 -259.292598)
		(width 0.088646)
		(layer "In6.Cu")
		(net "M_C_CPU0_SA_CB<7>")
	)
	(arc
		(start 337.887564 -258.478782)
		(mid 337.604862 -258.554524)
		(end 337.32216 -258.478782)
		(width 0.088646)
		(layer "In6.Cu")
		(net "M_C_CPU0_SA_CB<7>")
	)
	(arc
		(start 336.38236 -258.478782)
		(mid 336.195162 -258.428639)
		(end 336.007964 -258.478782)
		(width 0.088646)
		(layer "In6.Cu")
		(net "M_C_CPU0_SA_CB<7>")
	)
	(arc
		(start 342.96096 -258.478782)
		(mid 342.773762 -258.428639)
		(end 342.586564 -258.478782)
		(width 0.088646)
		(layer "In6.Cu")
		(net "M_C_CPU0_SA_CB<7>")
	)
	(arc
		(start 332.62316 -258.478782)
		(mid 332.435962 -258.428639)
		(end 332.248764 -258.478782)
		(width 0.088646)
		(layer "In6.Cu")
		(net "M_C_CPU0_SA_CB<7>")
	)
	(arc
		(start 335.44256 -258.478782)
		(mid 335.255362 -258.428639)
		(end 335.068164 -258.478782)
		(width 0.088646)
		(layer "In6.Cu")
		(net "M_C_CPU0_SA_CB<7>")
	)
	(arc
		(start 343.424764 -259.289042)
		(mid 343.222351 -259.082629)
		(end 343.148412 -258.80314)
		(width 0.088646)
		(layer "In6.Cu")
		(net "M_C_CPU0_SA_CB<7>")
	)
	(arc
		(start 342.586564 -258.478782)
		(mid 342.310005 -258.554491)
		(end 342.031828 -258.484878)
		(width 0.088646)
		(layer "In6.Cu")
		(net "M_C_CPU0_SA_CB<7>")
	)
	(arc
		(start 334.128364 -258.478782)
		(mid 333.845662 -258.554524)
		(end 333.56296 -258.478782)
		(width 0.088646)
		(layer "In6.Cu")
		(net "M_C_CPU0_SA_CB<7>")
	)
	(arc
		(start 336.007964 -258.478782)
		(mid 335.725262 -258.554524)
		(end 335.44256 -258.478782)
		(width 0.088646)
		(layer "In6.Cu")
		(net "M_C_CPU0_SA_CB<7>")
	)
	(arc
		(start 340.707218 -258.478782)
		(mid 340.424516 -258.554524)
		(end 340.141814 -258.478782)
		(width 0.088646)
		(layer "In6.Cu")
		(net "M_C_CPU0_SA_CB<7>")
	)
	(arc
		(start 332.248764 -258.478782)
		(mid 332.112398 -258.53526)
		(end 331.966062 -258.554474)
		(width 0.088646)
		(layer "In6.Cu")
		(net "M_C_CPU0_SA_CB<7>")
	)
	(arc
		(start 339.202014 -258.478782)
		(mid 339.014816 -258.428639)
		(end 338.827618 -258.478782)
		(width 0.088646)
		(layer "In6.Cu")
		(net "M_C_CPU0_SA_CB<7>")
	)
	(arc
		(start 340.141814 -258.478782)
		(mid 339.954616 -258.428639)
		(end 339.767418 -258.478782)
		(width 0.088646)
		(layer "In6.Cu")
		(net "M_C_CPU0_SA_CB<7>")
	)
	(arc
		(start 336.947764 -258.478782)
		(mid 336.665062 -258.554524)
		(end 336.38236 -258.478782)
		(width 0.088646)
		(layer "In6.Cu")
		(net "M_C_CPU0_SA_CB<7>")
	)
	(arc
		(start 338.817204 -258.484878)
		(mid 338.538772 -258.554692)
		(end 338.26196 -258.478782)
		(width 0.088646)
		(layer "In6.Cu")
		(net "M_C_CPU0_SA_CB<7>")
	)
	(arc
		(start 334.50276 -258.478782)
		(mid 334.315562 -258.428639)
		(end 334.128364 -258.478782)
		(width 0.088646)
		(layer "In6.Cu")
		(net "M_C_CPU0_SA_CB<7>")
	)
	(arc
		(start 343.148412 -258.80314)
		(mid 343.100733 -258.62024)
		(end 342.96985 -258.483862)
		(width 0.088646)
		(layer "In6.Cu")
		(net "M_C_CPU0_SA_CB<7>")
	)
	(arc
		(start 333.188564 -258.478782)
		(mid 332.905862 -258.554524)
		(end 332.62316 -258.478782)
		(width 0.088646)
		(layer "In6.Cu")
		(net "M_C_CPU0_SA_CB<7>")
	)
	(arc
		(start 341.647018 -258.478782)
		(mid 341.372789 -258.554707)
		(end 341.096346 -258.487418)
		(width 0.088646)
		(layer "In6.Cu")
		(net "M_C_CPU0_SA_CB<7>")
	)
	(arc
		(start 341.081614 -258.478782)
		(mid 340.894416 -258.428639)
		(end 340.707218 -258.478782)
		(width 0.088646)
		(layer "In6.Cu")
		(net "M_C_CPU0_SA_CB<7>")
	)
	(arc
		(start 344.275156 -258.868926)
		(mid 344.187868 -259.110882)
		(end 344.00236 -259.289042)
		(width 0.088646)
		(layer "In6.Cu")
		(net "M_C_CPU0_SA_CB<7>")
	)
	(arc
		(start 337.32216 -258.478782)
		(mid 337.134962 -258.428639)
		(end 336.947764 -258.478782)
		(width 0.088646)
		(layer "In6.Cu")
		(net "M_C_CPU0_SA_CB<7>")
	)
	(arc
		(start 342.021414 -258.478782)
		(mid 341.834216 -258.428639)
		(end 341.647018 -258.478782)
		(width 0.088646)
		(layer "In6.Cu")
		(net "M_C_CPU0_SA_CB<7>")
	)
	(arc
		(start 335.068164 -258.478782)
		(mid 334.785462 -258.554524)
		(end 334.50276 -258.478782)
		(width 0.088646)
		(layer "In6.Cu")
		(net "M_C_CPU0_SA_CB<7>")
	)
	(arc
		(start 333.56296 -258.478782)
		(mid 333.375762 -258.428639)
		(end 333.188564 -258.478782)
		(width 0.088646)
		(layer "In6.Cu")
		(net "M_C_CPU0_SA_CB<7>")
	)
	(arc
		(start 338.26196 -258.478782)
		(mid 338.074762 -258.428639)
		(end 337.887564 -258.478782)
		(width 0.088646)
		(layer "In6.Cu")
		(net "M_C_CPU0_SA_CB<7>")
	)
	(arc
		(start 339.767418 -258.478782)
		(mid 339.493189 -258.554707)
		(end 339.216746 -258.487418)
		(width 0.088646)
		(layer "In6.Cu")
		(net "M_C_CPU0_SA_CB<7>")
	)
	(segment
		(start 277.852886 -271.691862)
		(end 277.460456 -271.691862)
		(width 0.101854)
		(layer "F.Cu")
		(net "M_C_CPU0_SA_CB<6>")
	)
	(segment
		(start 280.689558 -272.161254)
		(end 280.689558 -271.835626)
		(width 0.20066)
		(layer "F.Cu")
		(net "M_C_CPU0_SA_CB<6>")
	)
	(segment
		(start 280.545794 -271.691862)
		(end 279.981152 -271.691862)
		(width 0.20066)
		(layer "F.Cu")
		(net "M_C_CPU0_SA_CB<6>")
	)
	(segment
		(start 280.689558 -271.835626)
		(end 280.545794 -271.691862)
		(width 0.20066)
		(layer "F.Cu")
		(net "M_C_CPU0_SA_CB<6>")
	)
	(segment
		(start 282.811982 -272.116804)
		(end 281.497278 -272.116804)
		(width 0.20066)
		(layer "F.Cu")
		(net "M_C_CPU0_SA_CB<6>")
	)
	(segment
		(start 280.856944 -272.32864)
		(end 280.689558 -272.161254)
		(width 0.20066)
		(layer "F.Cu")
		(net "M_C_CPU0_SA_CB<6>")
	)
	(segment
		(start 281.497278 -272.116804)
		(end 281.285442 -272.32864)
		(width 0.20066)
		(layer "F.Cu")
		(net "M_C_CPU0_SA_CB<6>")
	)
	(segment
		(start 345.123516 -259.616702)
		(end 345.123262 -259.616956)
		(width 0.20066)
		(layer "F.Cu")
		(net "M_C_CPU0_SA_CB<6>")
	)
	(segment
		(start 279.981152 -271.691862)
		(end 279.912826 -271.691862)
		(width 0.101854)
		(layer "F.Cu")
		(net "M_C_CPU0_SA_CB<6>")
	)
	(segment
		(start 281.285442 -272.32864)
		(end 280.856944 -272.32864)
		(width 0.20066)
		(layer "F.Cu")
		(net "M_C_CPU0_SA_CB<6>")
	)
	(segment
		(start 283.916882 -272.116804)
		(end 282.811982 -272.116804)
		(width 0.20066)
		(layer "F.Cu")
		(net "M_C_CPU0_SA_CB<6>")
	)
	(segment
		(start 277.460456 -271.691862)
		(end 276.840188 -271.691862)
		(width 0.20066)
		(layer "F.Cu")
		(net "M_C_CPU0_SA_CB<6>")
	)
	(segment
		(start 276.840188 -271.691862)
		(end 276.415246 -272.116804)
		(width 0.20066)
		(layer "F.Cu")
		(net "M_C_CPU0_SA_CB<6>")
	)
	(segment
		(start 345.123516 -259.081016)
		(end 345.123516 -259.616702)
		(width 0.20066)
		(layer "F.Cu")
		(net "M_C_CPU0_SA_CB<6>")
	)
	(segment
		(start 276.415246 -272.116804)
		(end 275.268182 -272.116804)
		(width 0.20066)
		(layer "F.Cu")
		(net "M_C_CPU0_SA_CB<6>")
	)
	(segment
		(start 279.912826 -271.691862)
		(end 277.852886 -271.691862)
		(width 0.1016)
		(layer "F.Cu")
		(net "M_C_CPU0_SA_CB<6>")
	)
	(segment
		(start 296.164508 -264.891012)
		(end 295.314624 -265.740896)
		(width 0.18288)
		(layer "In6.Cu")
		(net "M_C_CPU0_SA_CB<6>")
	)
	(segment
		(start 284.57906 -271.454626)
		(end 283.916882 -272.116804)
		(width 0.18288)
		(layer "In6.Cu")
		(net "M_C_CPU0_SA_CB<6>")
	)
	(segment
		(start 342.608916 -259.375148)
		(end 342.533224 -259.318252)
		(width 0.088646)
		(layer "In6.Cu")
		(net "M_C_CPU0_SA_CB<6>")
	)
	(segment
		(start 294.139112 -265.740896)
		(end 293.493698 -266.38631)
		(width 0.18288)
		(layer "In6.Cu")
		(net "M_C_CPU0_SA_CB<6>")
	)
	(segment
		(start 305.125882 -264.808208)
		(end 304.943002 -264.625328)
		(width 0.18288)
		(layer "In6.Cu")
		(net "M_C_CPU0_SA_CB<6>")
	)
	(segment
		(start 329.12939 -260.267958)
		(end 326.029828 -261.551674)
		(width 0.18288)
		(layer "In6.Cu")
		(net "M_C_CPU0_SA_CB<6>")
	)
	(segment
		(start 331.00899 -260.267958)
		(end 330.598018 -260.267958)
		(width 0.088646)
		(layer "In6.Cu")
		(net "M_C_CPU0_SA_CB<6>")
	)
	(segment
		(start 293.493698 -266.38631)
		(end 292.416484 -266.38631)
		(width 0.18288)
		(layer "In6.Cu")
		(net "M_C_CPU0_SA_CB<6>")
	)
	(segment
		(start 302.79213 -264.891012)
		(end 301.729902 -264.891012)
		(width 0.18288)
		(layer "In6.Cu")
		(net "M_C_CPU0_SA_CB<6>")
	)
	(segment
		(start 305.633882 -264.193528)
		(end 305.633882 -264.625328)
		(width 0.18288)
		(layer "In6.Cu")
		(net "M_C_CPU0_SA_CB<6>")
	)
	(segment
		(start 311.401206 -263.191752)
		(end 311.241186 -263.351772)
		(width 0.18288)
		(layer "In6.Cu")
		(net "M_C_CPU0_SA_CB<6>")
	)
	(segment
		(start 291.960808 -266.841986)
		(end 291.960808 -267.246354)
		(width 0.18288)
		(layer "In6.Cu")
		(net "M_C_CPU0_SA_CB<6>")
	)
	(segment
		(start 311.241186 -263.351772)
		(end 311.241186 -263.928352)
		(width 0.18288)
		(layer "In6.Cu")
		(net "M_C_CPU0_SA_CB<6>")
	)
	(segment
		(start 291.960808 -267.246354)
		(end 291.767514 -267.439648)
		(width 0.18288)
		(layer "In6.Cu")
		(net "M_C_CPU0_SA_CB<6>")
	)
	(segment
		(start 313.899804 -262.184642)
		(end 312.892694 -263.191752)
		(width 0.18288)
		(layer "In6.Cu")
		(net "M_C_CPU0_SA_CB<6>")
	)
	(segment
		(start 315.783214 -261.551674)
		(end 315.150246 -262.184642)
		(width 0.18288)
		(layer "In6.Cu")
		(net "M_C_CPU0_SA_CB<6>")
	)
	(segment
		(start 288.229294 -269.879826)
		(end 287.213294 -269.879826)
		(width 0.18288)
		(layer "In6.Cu")
		(net "M_C_CPU0_SA_CB<6>")
	)
	(segment
		(start 303.672494 -264.010648)
		(end 302.79213 -264.891012)
		(width 0.18288)
		(layer "In6.Cu")
		(net "M_C_CPU0_SA_CB<6>")
	)
	(segment
		(start 304.943002 -264.193528)
		(end 304.760122 -264.010648)
		(width 0.18288)
		(layer "In6.Cu")
		(net "M_C_CPU0_SA_CB<6>")
	)
	(segment
		(start 289.829494 -269.092426)
		(end 289.016694 -269.092426)
		(width 0.18288)
		(layer "In6.Cu")
		(net "M_C_CPU0_SA_CB<6>")
	)
	(segment
		(start 311.081166 -264.088372)
		(end 310.707786 -264.088372)
		(width 0.18288)
		(layer "In6.Cu")
		(net "M_C_CPU0_SA_CB<6>")
	)
	(segment
		(start 300.673262 -264.891012)
		(end 296.164508 -264.891012)
		(width 0.18288)
		(layer "In6.Cu")
		(net "M_C_CPU0_SA_CB<6>")
	)
	(segment
		(start 312.892694 -263.191752)
		(end 311.401206 -263.191752)
		(width 0.18288)
		(layer "In6.Cu")
		(net "M_C_CPU0_SA_CB<6>")
	)
	(segment
		(start 330.598018 -260.267958)
		(end 329.12939 -260.267958)
		(width 0.18288)
		(layer "In6.Cu")
		(net "M_C_CPU0_SA_CB<6>")
	)
	(segment
		(start 285.638494 -271.454626)
		(end 284.57906 -271.454626)
		(width 0.18288)
		(layer "In6.Cu")
		(net "M_C_CPU0_SA_CB<6>")
	)
	(segment
		(start 308.346094 -264.645648)
		(end 307.380894 -264.645648)
		(width 0.18288)
		(layer "In6.Cu")
		(net "M_C_CPU0_SA_CB<6>")
	)
	(segment
		(start 342.116664 -259.292598)
		(end 342.101932 -259.301234)
		(width 0.088646)
		(layer "In6.Cu")
		(net "M_C_CPU0_SA_CB<6>")
	)
	(segment
		(start 310.547766 -263.351772)
		(end 310.387746 -263.191752)
		(width 0.18288)
		(layer "In6.Cu")
		(net "M_C_CPU0_SA_CB<6>")
	)
	(segment
		(start 287.213294 -269.879826)
		(end 285.638494 -271.454626)
		(width 0.18288)
		(layer "In6.Cu")
		(net "M_C_CPU0_SA_CB<6>")
	)
	(segment
		(start 340.237064 -259.292598)
		(end 340.22665 -259.298694)
		(width 0.088646)
		(layer "In6.Cu")
		(net "M_C_CPU0_SA_CB<6>")
	)
	(segment
		(start 339.297518 -259.292598)
		(end 339.287104 -259.298694)
		(width 0.088646)
		(layer "In6.Cu")
		(net "M_C_CPU0_SA_CB<6>")
	)
	(segment
		(start 326.029828 -261.551674)
		(end 315.783214 -261.551674)
		(width 0.18288)
		(layer "In6.Cu")
		(net "M_C_CPU0_SA_CB<6>")
	)
	(segment
		(start 290.743894 -268.178026)
		(end 289.829494 -269.092426)
		(width 0.18288)
		(layer "In6.Cu")
		(net "M_C_CPU0_SA_CB<6>")
	)
	(segment
		(start 307.380894 -264.645648)
		(end 306.745894 -264.010648)
		(width 0.18288)
		(layer "In6.Cu")
		(net "M_C_CPU0_SA_CB<6>")
	)
	(segment
		(start 332.38948 -259.366512)
		(end 331.910436 -259.366512)
		(width 0.088646)
		(layer "In6.Cu")
		(net "M_C_CPU0_SA_CB<6>")
	)
	(segment
		(start 310.547766 -263.928352)
		(end 310.547766 -263.351772)
		(width 0.18288)
		(layer "In6.Cu")
		(net "M_C_CPU0_SA_CB<6>")
	)
	(segment
		(start 289.016694 -269.092426)
		(end 288.229294 -269.879826)
		(width 0.18288)
		(layer "In6.Cu")
		(net "M_C_CPU0_SA_CB<6>")
	)
	(segment
		(start 310.387746 -263.191752)
		(end 309.79999 -263.191752)
		(width 0.18288)
		(layer "In6.Cu")
		(net "M_C_CPU0_SA_CB<6>")
	)
	(segment
		(start 315.150246 -262.184642)
		(end 313.899804 -262.184642)
		(width 0.18288)
		(layer "In6.Cu")
		(net "M_C_CPU0_SA_CB<6>")
	)
	(segment
		(start 305.633882 -264.625328)
		(end 305.451002 -264.808208)
		(width 0.18288)
		(layer "In6.Cu")
		(net "M_C_CPU0_SA_CB<6>")
	)
	(segment
		(start 342.786716 -259.605272)
		(end 342.732868 -259.50799)
		(width 0.088646)
		(layer "In6.Cu")
		(net "M_C_CPU0_SA_CB<6>")
	)
	(segment
		(start 341.176864 -259.292598)
		(end 341.162132 -259.301234)
		(width 0.088646)
		(layer "In6.Cu")
		(net "M_C_CPU0_SA_CB<6>")
	)
	(segment
		(start 291.767514 -267.439648)
		(end 290.906962 -267.439648)
		(width 0.18288)
		(layer "In6.Cu")
		(net "M_C_CPU0_SA_CB<6>")
	)
	(segment
		(start 301.729902 -264.891012)
		(end 301.547022 -265.073892)
		(width 0.18288)
		(layer "In6.Cu")
		(net "M_C_CPU0_SA_CB<6>")
	)
	(segment
		(start 305.816762 -264.010648)
		(end 305.633882 -264.193528)
		(width 0.18288)
		(layer "In6.Cu")
		(net "M_C_CPU0_SA_CB<6>")
	)
	(segment
		(start 306.745894 -264.010648)
		(end 305.816762 -264.010648)
		(width 0.18288)
		(layer "In6.Cu")
		(net "M_C_CPU0_SA_CB<6>")
	)
	(segment
		(start 290.906962 -267.439648)
		(end 290.743894 -267.602716)
		(width 0.18288)
		(layer "In6.Cu")
		(net "M_C_CPU0_SA_CB<6>")
	)
	(segment
		(start 290.743894 -267.602716)
		(end 290.743894 -268.178026)
		(width 0.18288)
		(layer "In6.Cu")
		(net "M_C_CPU0_SA_CB<6>")
	)
	(segment
		(start 342.533224 -259.318252)
		(end 342.49106 -259.292598)
		(width 0.088646)
		(layer "In6.Cu")
		(net "M_C_CPU0_SA_CB<6>")
	)
	(segment
		(start 292.416484 -266.38631)
		(end 291.960808 -266.841986)
		(width 0.18288)
		(layer "In6.Cu")
		(net "M_C_CPU0_SA_CB<6>")
	)
	(segment
		(start 304.760122 -264.010648)
		(end 303.672494 -264.010648)
		(width 0.18288)
		(layer "In6.Cu")
		(net "M_C_CPU0_SA_CB<6>")
	)
	(segment
		(start 300.856142 -265.29411)
		(end 300.856142 -265.073892)
		(width 0.18288)
		(layer "In6.Cu")
		(net "M_C_CPU0_SA_CB<6>")
	)
	(segment
		(start 309.79999 -263.191752)
		(end 308.346094 -264.645648)
		(width 0.18288)
		(layer "In6.Cu")
		(net "M_C_CPU0_SA_CB<6>")
	)
	(segment
		(start 304.943002 -264.625328)
		(end 304.943002 -264.193528)
		(width 0.18288)
		(layer "In6.Cu")
		(net "M_C_CPU0_SA_CB<6>")
	)
	(segment
		(start 300.856142 -265.073892)
		(end 300.673262 -264.891012)
		(width 0.18288)
		(layer "In6.Cu")
		(net "M_C_CPU0_SA_CB<6>")
	)
	(segment
		(start 301.039022 -265.47699)
		(end 300.856142 -265.29411)
		(width 0.18288)
		(layer "In6.Cu")
		(net "M_C_CPU0_SA_CB<6>")
	)
	(segment
		(start 301.547022 -265.29411)
		(end 301.364142 -265.47699)
		(width 0.18288)
		(layer "In6.Cu")
		(net "M_C_CPU0_SA_CB<6>")
	)
	(segment
		(start 311.241186 -263.928352)
		(end 311.081166 -264.088372)
		(width 0.18288)
		(layer "In6.Cu")
		(net "M_C_CPU0_SA_CB<6>")
	)
	(segment
		(start 295.314624 -265.740896)
		(end 294.139112 -265.740896)
		(width 0.18288)
		(layer "In6.Cu")
		(net "M_C_CPU0_SA_CB<6>")
	)
	(segment
		(start 310.707786 -264.088372)
		(end 310.547766 -263.928352)
		(width 0.18288)
		(layer "In6.Cu")
		(net "M_C_CPU0_SA_CB<6>")
	)
	(segment
		(start 301.547022 -265.073892)
		(end 301.547022 -265.29411)
		(width 0.18288)
		(layer "In6.Cu")
		(net "M_C_CPU0_SA_CB<6>")
	)
	(segment
		(start 342.732868 -259.50799)
		(end 342.608916 -259.375148)
		(width 0.088646)
		(layer "In6.Cu")
		(net "M_C_CPU0_SA_CB<6>")
	)
	(segment
		(start 301.364142 -265.47699)
		(end 301.039022 -265.47699)
		(width 0.18288)
		(layer "In6.Cu")
		(net "M_C_CPU0_SA_CB<6>")
	)
	(segment
		(start 331.910436 -259.366512)
		(end 331.00899 -260.267958)
		(width 0.088646)
		(layer "In6.Cu")
		(net "M_C_CPU0_SA_CB<6>")
	)
	(segment
		(start 305.451002 -264.808208)
		(end 305.125882 -264.808208)
		(width 0.18288)
		(layer "In6.Cu")
		(net "M_C_CPU0_SA_CB<6>")
	)
	(arc
		(start 337.79206 -259.292598)
		(mid 337.604862 -259.242455)
		(end 337.417664 -259.292598)
		(width 0.088646)
		(layer "In6.Cu")
		(net "M_C_CPU0_SA_CB<6>")
	)
	(arc
		(start 333.09306 -259.292598)
		(mid 332.905862 -259.242455)
		(end 332.718664 -259.292598)
		(width 0.088646)
		(layer "In6.Cu")
		(net "M_C_CPU0_SA_CB<6>")
	)
	(arc
		(start 343.056464 -259.941314)
		(mid 342.927733 -259.833439)
		(end 342.843612 -259.688076)
		(width 0.088646)
		(layer "In6.Cu")
		(net "M_C_CPU0_SA_CB<6>")
	)
	(arc
		(start 337.417664 -259.292598)
		(mid 337.134962 -259.368374)
		(end 336.85226 -259.292598)
		(width 0.088646)
		(layer "In6.Cu")
		(net "M_C_CPU0_SA_CB<6>")
	)
	(arc
		(start 342.843612 -259.688076)
		(mid 342.815731 -259.646284)
		(end 342.786716 -259.605272)
		(width 0.088646)
		(layer "In6.Cu")
		(net "M_C_CPU0_SA_CB<6>")
	)
	(arc
		(start 344.33637 -259.973826)
		(mid 344.300349 -259.976425)
		(end 344.264742 -259.982462)
		(width 0.088646)
		(layer "In6.Cu")
		(net "M_C_CPU0_SA_CB<6>")
	)
	(arc
		(start 333.658464 -259.292598)
		(mid 333.375762 -259.368374)
		(end 333.09306 -259.292598)
		(width 0.088646)
		(layer "In6.Cu")
		(net "M_C_CPU0_SA_CB<6>")
	)
	(arc
		(start 343.914222 -259.90169)
		(mid 343.668084 -259.867064)
		(end 343.43086 -259.941314)
		(width 0.088646)
		(layer "In6.Cu")
		(net "M_C_CPU0_SA_CB<6>")
	)
	(arc
		(start 341.55126 -259.292598)
		(mid 341.364062 -259.242455)
		(end 341.176864 -259.292598)
		(width 0.088646)
		(layer "In6.Cu")
		(net "M_C_CPU0_SA_CB<6>")
	)
	(arc
		(start 342.49106 -259.292598)
		(mid 342.303862 -259.242455)
		(end 342.116664 -259.292598)
		(width 0.088646)
		(layer "In6.Cu")
		(net "M_C_CPU0_SA_CB<6>")
	)
	(arc
		(start 338.357464 -259.292598)
		(mid 338.074762 -259.368374)
		(end 337.79206 -259.292598)
		(width 0.088646)
		(layer "In6.Cu")
		(net "M_C_CPU0_SA_CB<6>")
	)
	(arc
		(start 344.264742 -259.982462)
		(mid 344.12536 -259.987046)
		(end 343.993978 -259.940298)
		(width 0.088646)
		(layer "In6.Cu")
		(net "M_C_CPU0_SA_CB<6>")
	)
	(arc
		(start 335.538064 -259.292598)
		(mid 335.255362 -259.368374)
		(end 334.97266 -259.292598)
		(width 0.088646)
		(layer "In6.Cu")
		(net "M_C_CPU0_SA_CB<6>")
	)
	(arc
		(start 334.03286 -259.292598)
		(mid 333.845662 -259.242455)
		(end 333.658464 -259.292598)
		(width 0.088646)
		(layer "In6.Cu")
		(net "M_C_CPU0_SA_CB<6>")
	)
	(arc
		(start 343.43086 -259.941314)
		(mid 343.243662 -259.991457)
		(end 343.056464 -259.941314)
		(width 0.088646)
		(layer "In6.Cu")
		(net "M_C_CPU0_SA_CB<6>")
	)
	(arc
		(start 335.91246 -259.292598)
		(mid 335.725262 -259.242455)
		(end 335.538064 -259.292598)
		(width 0.088646)
		(layer "In6.Cu")
		(net "M_C_CPU0_SA_CB<6>")
	)
	(arc
		(start 341.162132 -259.301234)
		(mid 340.885657 -259.368554)
		(end 340.61146 -259.292598)
		(width 0.088646)
		(layer "In6.Cu")
		(net "M_C_CPU0_SA_CB<6>")
	)
	(arc
		(start 338.73186 -259.292598)
		(mid 338.544662 -259.242455)
		(end 338.357464 -259.292598)
		(width 0.088646)
		(layer "In6.Cu")
		(net "M_C_CPU0_SA_CB<6>")
	)
	(arc
		(start 336.477864 -259.292598)
		(mid 336.195162 -259.368374)
		(end 335.91246 -259.292598)
		(width 0.088646)
		(layer "In6.Cu")
		(net "M_C_CPU0_SA_CB<6>")
	)
	(arc
		(start 339.287104 -259.298694)
		(mid 339.008672 -259.36854)
		(end 338.73186 -259.292598)
		(width 0.088646)
		(layer "In6.Cu")
		(net "M_C_CPU0_SA_CB<6>")
	)
	(arc
		(start 339.671914 -259.292598)
		(mid 339.484716 -259.242455)
		(end 339.297518 -259.292598)
		(width 0.088646)
		(layer "In6.Cu")
		(net "M_C_CPU0_SA_CB<6>")
	)
	(arc
		(start 334.97266 -259.292598)
		(mid 334.785462 -259.242455)
		(end 334.598264 -259.292598)
		(width 0.088646)
		(layer "In6.Cu")
		(net "M_C_CPU0_SA_CB<6>")
	)
	(arc
		(start 345.123262 -259.616956)
		(mid 344.765981 -259.875138)
		(end 344.33637 -259.973826)
		(width 0.088646)
		(layer "In6.Cu")
		(net "M_C_CPU0_SA_CB<6>")
	)
	(arc
		(start 340.61146 -259.292598)
		(mid 340.424262 -259.242455)
		(end 340.237064 -259.292598)
		(width 0.088646)
		(layer "In6.Cu")
		(net "M_C_CPU0_SA_CB<6>")
	)
	(arc
		(start 332.718664 -259.292598)
		(mid 332.559713 -259.354661)
		(end 332.38948 -259.366512)
		(width 0.088646)
		(layer "In6.Cu")
		(net "M_C_CPU0_SA_CB<6>")
	)
	(arc
		(start 334.598264 -259.292598)
		(mid 334.315562 -259.368374)
		(end 334.03286 -259.292598)
		(width 0.088646)
		(layer "In6.Cu")
		(net "M_C_CPU0_SA_CB<6>")
	)
	(arc
		(start 340.22665 -259.298694)
		(mid 339.948472 -259.368417)
		(end 339.671914 -259.292598)
		(width 0.088646)
		(layer "In6.Cu")
		(net "M_C_CPU0_SA_CB<6>")
	)
	(arc
		(start 343.993978 -259.940298)
		(mid 343.954913 -259.919315)
		(end 343.914222 -259.90169)
		(width 0.088646)
		(layer "In6.Cu")
		(net "M_C_CPU0_SA_CB<6>")
	)
	(arc
		(start 336.85226 -259.292598)
		(mid 336.665062 -259.242455)
		(end 336.477864 -259.292598)
		(width 0.088646)
		(layer "In6.Cu")
		(net "M_C_CPU0_SA_CB<6>")
	)
	(arc
		(start 342.101932 -259.301234)
		(mid 341.825457 -259.368554)
		(end 341.55126 -259.292598)
		(width 0.088646)
		(layer "In6.Cu")
		(net "M_C_CPU0_SA_CB<6>")
	)
	(segment
		(start 273.37258 -271.323562)
		(end 273.218148 -271.477994)
		(width 0.20066)
		(layer "F.Cu")
		(net "M_C_CPU0_SA_CB<5>")
	)
	(segment
		(start 343.713562 -258.2672)
		(end 343.713562 -258.802886)
		(width 0.20066)
		(layer "F.Cu")
		(net "M_C_CPU0_SA_CB<5>")
	)
	(segment
		(start 273.53514 -270.841724)
		(end 273.37258 -271.004284)
		(width 0.20066)
		(layer "F.Cu")
		(net "M_C_CPU0_SA_CB<5>")
	)
	(segment
		(start 277.072598 -271.266666)
		(end 276.647656 -270.841724)
		(width 0.20066)
		(layer "F.Cu")
		(net "M_C_CPU0_SA_CB<5>")
	)
	(segment
		(start 274.022566 -270.841724)
		(end 273.53514 -270.841724)
		(width 0.20066)
		(layer "F.Cu")
		(net "M_C_CPU0_SA_CB<5>")
	)
	(segment
		(start 279.816814 -271.266666)
		(end 278.711914 -271.266666)
		(width 0.20066)
		(layer "F.Cu")
		(net "M_C_CPU0_SA_CB<5>")
	)
	(segment
		(start 343.713562 -258.802886)
		(end 343.713816 -258.80314)
		(width 0.20066)
		(layer "F.Cu")
		(net "M_C_CPU0_SA_CB<5>")
	)
	(segment
		(start 276.138386 -270.841724)
		(end 274.152868 -270.841724)
		(width 0.1016)
		(layer "F.Cu")
		(net "M_C_CPU0_SA_CB<5>")
	)
	(segment
		(start 273.218148 -271.477994)
		(end 272.713704 -271.477994)
		(width 0.20066)
		(layer "F.Cu")
		(net "M_C_CPU0_SA_CB<5>")
	)
	(segment
		(start 272.502376 -271.266666)
		(end 271.168114 -271.266666)
		(width 0.20066)
		(layer "F.Cu")
		(net "M_C_CPU0_SA_CB<5>")
	)
	(segment
		(start 272.713704 -271.477994)
		(end 272.502376 -271.266666)
		(width 0.20066)
		(layer "F.Cu")
		(net "M_C_CPU0_SA_CB<5>")
	)
	(segment
		(start 274.152868 -270.841724)
		(end 274.022566 -270.841724)
		(width 0.101854)
		(layer "F.Cu")
		(net "M_C_CPU0_SA_CB<5>")
	)
	(segment
		(start 273.37258 -271.004284)
		(end 273.37258 -271.323562)
		(width 0.20066)
		(layer "F.Cu")
		(net "M_C_CPU0_SA_CB<5>")
	)
	(segment
		(start 278.711914 -271.266666)
		(end 277.072598 -271.266666)
		(width 0.20066)
		(layer "F.Cu")
		(net "M_C_CPU0_SA_CB<5>")
	)
	(segment
		(start 276.647656 -270.841724)
		(end 276.543262 -270.841724)
		(width 0.20066)
		(layer "F.Cu")
		(net "M_C_CPU0_SA_CB<5>")
	)
	(segment
		(start 276.543262 -270.841724)
		(end 276.138386 -270.841724)
		(width 0.101854)
		(layer "F.Cu")
		(net "M_C_CPU0_SA_CB<5>")
	)
	(segment
		(start 305.339242 -260.943852)
		(end 305.179222 -261.103872)
		(width 0.18288)
		(layer "In6.Cu")
		(net "M_C_CPU0_SA_CB<5>")
	)
	(segment
		(start 288.445448 -264.98804)
		(end 285.927546 -267.505942)
		(width 0.18288)
		(layer "In6.Cu")
		(net "M_C_CPU0_SA_CB<5>")
	)
	(segment
		(start 344.02649 -258.80314)
		(end 344.083894 -258.860544)
		(width 0.088646)
		(layer "In6.Cu")
		(net "M_C_CPU0_SA_CB<5>")
	)
	(segment
		(start 305.872642 -261.329932)
		(end 305.872642 -261.103872)
		(width 0.18288)
		(layer "In6.Cu")
		(net "M_C_CPU0_SA_CB<5>")
	)
	(segment
		(start 331.028802 -258.733798)
		(end 328.928222 -258.733798)
		(width 0.18288)
		(layer "In6.Cu")
		(net "M_C_CPU0_SA_CB<5>")
	)
	(segment
		(start 295.24833 -263.190736)
		(end 292.0492 -263.190736)
		(width 0.18288)
		(layer "In6.Cu")
		(net "M_C_CPU0_SA_CB<5>")
	)
	(segment
		(start 307.881274 -260.832346)
		(end 307.223668 -261.489952)
		(width 0.18288)
		(layer "In6.Cu")
		(net "M_C_CPU0_SA_CB<5>")
	)
	(segment
		(start 343.909904 -259.122418)
		(end 343.901014 -259.127498)
		(width 0.088646)
		(layer "In6.Cu")
		(net "M_C_CPU0_SA_CB<5>")
	)
	(segment
		(start 280.758392 -271.266666)
		(end 279.816814 -271.266666)
		(width 0.18288)
		(layer "In6.Cu")
		(net "M_C_CPU0_SA_CB<5>")
	)
	(segment
		(start 310.413654 -260.832346)
		(end 307.881274 -260.832346)
		(width 0.18288)
		(layer "In6.Cu")
		(net "M_C_CPU0_SA_CB<5>")
	)
	(segment
		(start 299.870368 -261.489952)
		(end 299.621194 -261.739126)
		(width 0.18288)
		(layer "In6.Cu")
		(net "M_C_CPU0_SA_CB<5>")
	)
	(segment
		(start 331.84719 -258.364228)
		(end 331.47762 -258.733798)
		(width 0.088646)
		(layer "In6.Cu")
		(net "M_C_CPU0_SA_CB<5>")
	)
	(segment
		(start 305.712622 -260.943852)
		(end 305.339242 -260.943852)
		(width 0.18288)
		(layer "In6.Cu")
		(net "M_C_CPU0_SA_CB<5>")
	)
	(segment
		(start 285.927546 -267.505942)
		(end 285.927546 -268.586712)
		(width 0.18288)
		(layer "In6.Cu")
		(net "M_C_CPU0_SA_CB<5>")
	)
	(segment
		(start 285.927546 -268.586712)
		(end 285.371794 -269.142464)
		(width 0.18288)
		(layer "In6.Cu")
		(net "M_C_CPU0_SA_CB<5>")
	)
	(segment
		(start 299.621194 -262.066532)
		(end 299.346874 -262.340852)
		(width 0.18288)
		(layer "In6.Cu")
		(net "M_C_CPU0_SA_CB<5>")
	)
	(segment
		(start 331.966062 -258.364228)
		(end 331.84719 -258.364228)
		(width 0.088646)
		(layer "In6.Cu")
		(net "M_C_CPU0_SA_CB<5>")
	)
	(segment
		(start 285.371794 -269.142464)
		(end 282.882594 -269.142464)
		(width 0.18288)
		(layer "In6.Cu")
		(net "M_C_CPU0_SA_CB<5>")
	)
	(segment
		(start 305.872642 -261.103872)
		(end 305.712622 -260.943852)
		(width 0.18288)
		(layer "In6.Cu")
		(net "M_C_CPU0_SA_CB<5>")
	)
	(segment
		(start 328.928222 -258.733798)
		(end 325.777098 -260.03885)
		(width 0.18288)
		(layer "In6.Cu")
		(net "M_C_CPU0_SA_CB<5>")
	)
	(segment
		(start 305.019202 -261.489952)
		(end 299.870368 -261.489952)
		(width 0.18288)
		(layer "In6.Cu")
		(net "M_C_CPU0_SA_CB<5>")
	)
	(segment
		(start 307.223668 -261.489952)
		(end 306.032662 -261.489952)
		(width 0.18288)
		(layer "In6.Cu")
		(net "M_C_CPU0_SA_CB<5>")
	)
	(segment
		(start 331.47762 -258.733798)
		(end 331.028802 -258.733798)
		(width 0.088646)
		(layer "In6.Cu")
		(net "M_C_CPU0_SA_CB<5>")
	)
	(segment
		(start 305.179222 -261.329932)
		(end 305.019202 -261.489952)
		(width 0.18288)
		(layer "In6.Cu")
		(net "M_C_CPU0_SA_CB<5>")
	)
	(segment
		(start 325.777098 -260.03885)
		(end 311.20715 -260.03885)
		(width 0.18288)
		(layer "In6.Cu")
		(net "M_C_CPU0_SA_CB<5>")
	)
	(segment
		(start 299.346874 -262.340852)
		(end 296.098214 -262.340852)
		(width 0.18288)
		(layer "In6.Cu")
		(net "M_C_CPU0_SA_CB<5>")
	)
	(segment
		(start 292.0492 -263.190736)
		(end 290.251896 -264.98804)
		(width 0.18288)
		(layer "In6.Cu")
		(net "M_C_CPU0_SA_CB<5>")
	)
	(segment
		(start 296.098214 -262.340852)
		(end 295.24833 -263.190736)
		(width 0.18288)
		(layer "In6.Cu")
		(net "M_C_CPU0_SA_CB<5>")
	)
	(segment
		(start 343.713816 -258.80314)
		(end 344.02649 -258.80314)
		(width 0.088646)
		(layer "In6.Cu")
		(net "M_C_CPU0_SA_CB<5>")
	)
	(segment
		(start 342.116664 -258.313428)
		(end 342.101932 -258.304792)
		(width 0.088646)
		(layer "In6.Cu")
		(net "M_C_CPU0_SA_CB<5>")
	)
	(segment
		(start 337.802474 -258.307332)
		(end 337.79206 -258.313428)
		(width 0.088646)
		(layer "In6.Cu")
		(net "M_C_CPU0_SA_CB<5>")
	)
	(segment
		(start 340.237318 -258.313428)
		(end 340.226904 -258.307332)
		(width 0.088646)
		(layer "In6.Cu")
		(net "M_C_CPU0_SA_CB<5>")
	)
	(segment
		(start 341.176864 -258.313428)
		(end 341.16645 -258.307332)
		(width 0.088646)
		(layer "In6.Cu")
		(net "M_C_CPU0_SA_CB<5>")
	)
	(segment
		(start 339.297264 -258.313428)
		(end 339.28685 -258.307332)
		(width 0.088646)
		(layer "In6.Cu")
		(net "M_C_CPU0_SA_CB<5>")
	)
	(segment
		(start 311.20715 -260.03885)
		(end 310.413654 -260.832346)
		(width 0.18288)
		(layer "In6.Cu")
		(net "M_C_CPU0_SA_CB<5>")
	)
	(segment
		(start 306.032662 -261.489952)
		(end 305.872642 -261.329932)
		(width 0.18288)
		(layer "In6.Cu")
		(net "M_C_CPU0_SA_CB<5>")
	)
	(segment
		(start 290.251896 -264.98804)
		(end 288.445448 -264.98804)
		(width 0.18288)
		(layer "In6.Cu")
		(net "M_C_CPU0_SA_CB<5>")
	)
	(segment
		(start 299.621194 -261.739126)
		(end 299.621194 -262.066532)
		(width 0.18288)
		(layer "In6.Cu")
		(net "M_C_CPU0_SA_CB<5>")
	)
	(segment
		(start 282.882594 -269.142464)
		(end 280.758392 -271.266666)
		(width 0.18288)
		(layer "In6.Cu")
		(net "M_C_CPU0_SA_CB<5>")
	)
	(segment
		(start 343.526618 -259.127498)
		(end 343.517728 -259.122418)
		(width 0.088646)
		(layer "In6.Cu")
		(net "M_C_CPU0_SA_CB<5>")
	)
	(segment
		(start 343.339166 -258.80314)
		(end 343.339166 -258.79552)
		(width 0.088646)
		(layer "In6.Cu")
		(net "M_C_CPU0_SA_CB<5>")
	)
	(segment
		(start 305.179222 -261.103872)
		(end 305.179222 -261.329932)
		(width 0.18288)
		(layer "In6.Cu")
		(net "M_C_CPU0_SA_CB<5>")
	)
	(arc
		(start 341.16645 -258.307332)
		(mid 340.888272 -258.23764)
		(end 340.611714 -258.313428)
		(width 0.088646)
		(layer "In6.Cu")
		(net "M_C_CPU0_SA_CB<5>")
	)
	(arc
		(start 343.517728 -259.122418)
		(mid 343.386814 -258.986058)
		(end 343.339166 -258.80314)
		(width 0.088646)
		(layer "In6.Cu")
		(net "M_C_CPU0_SA_CB<5>")
	)
	(arc
		(start 340.611714 -258.313428)
		(mid 340.424516 -258.363571)
		(end 340.237318 -258.313428)
		(width 0.088646)
		(layer "In6.Cu")
		(net "M_C_CPU0_SA_CB<5>")
	)
	(arc
		(start 338.732114 -258.313428)
		(mid 338.544916 -258.363571)
		(end 338.357718 -258.313428)
		(width 0.088646)
		(layer "In6.Cu")
		(net "M_C_CPU0_SA_CB<5>")
	)
	(arc
		(start 337.417664 -258.313428)
		(mid 337.134962 -258.237686)
		(end 336.85226 -258.313428)
		(width 0.088646)
		(layer "In6.Cu")
		(net "M_C_CPU0_SA_CB<5>")
	)
	(arc
		(start 336.477864 -258.313428)
		(mid 336.195162 -258.237686)
		(end 335.91246 -258.313428)
		(width 0.088646)
		(layer "In6.Cu")
		(net "M_C_CPU0_SA_CB<5>")
	)
	(arc
		(start 338.357718 -258.313428)
		(mid 338.080905 -258.237592)
		(end 337.802474 -258.307332)
		(width 0.088646)
		(layer "In6.Cu")
		(net "M_C_CPU0_SA_CB<5>")
	)
	(arc
		(start 339.28685 -258.307332)
		(mid 339.008672 -258.23764)
		(end 338.732114 -258.313428)
		(width 0.088646)
		(layer "In6.Cu")
		(net "M_C_CPU0_SA_CB<5>")
	)
	(arc
		(start 342.49106 -258.313428)
		(mid 342.303862 -258.363571)
		(end 342.116664 -258.313428)
		(width 0.088646)
		(layer "In6.Cu")
		(net "M_C_CPU0_SA_CB<5>")
	)
	(arc
		(start 336.85226 -258.313428)
		(mid 336.665062 -258.363571)
		(end 336.477864 -258.313428)
		(width 0.088646)
		(layer "In6.Cu")
		(net "M_C_CPU0_SA_CB<5>")
	)
	(arc
		(start 332.15326 -258.313428)
		(mid 332.063004 -258.35115)
		(end 331.966062 -258.364228)
		(width 0.088646)
		(layer "In6.Cu")
		(net "M_C_CPU0_SA_CB<5>")
	)
	(arc
		(start 340.226904 -258.307332)
		(mid 339.948472 -258.237518)
		(end 339.67166 -258.313428)
		(width 0.088646)
		(layer "In6.Cu")
		(net "M_C_CPU0_SA_CB<5>")
	)
	(arc
		(start 343.056464 -258.313428)
		(mid 342.773762 -258.237686)
		(end 342.49106 -258.313428)
		(width 0.088646)
		(layer "In6.Cu")
		(net "M_C_CPU0_SA_CB<5>")
	)
	(arc
		(start 339.67166 -258.313428)
		(mid 339.484462 -258.363571)
		(end 339.297264 -258.313428)
		(width 0.088646)
		(layer "In6.Cu")
		(net "M_C_CPU0_SA_CB<5>")
	)
	(arc
		(start 333.658464 -258.313428)
		(mid 333.375762 -258.237686)
		(end 333.09306 -258.313428)
		(width 0.088646)
		(layer "In6.Cu")
		(net "M_C_CPU0_SA_CB<5>")
	)
	(arc
		(start 334.03286 -258.313428)
		(mid 333.845662 -258.363571)
		(end 333.658464 -258.313428)
		(width 0.088646)
		(layer "In6.Cu")
		(net "M_C_CPU0_SA_CB<5>")
	)
	(arc
		(start 334.97266 -258.313428)
		(mid 334.785462 -258.363571)
		(end 334.598264 -258.313428)
		(width 0.088646)
		(layer "In6.Cu")
		(net "M_C_CPU0_SA_CB<5>")
	)
	(arc
		(start 341.55126 -258.313428)
		(mid 341.364062 -258.363571)
		(end 341.176864 -258.313428)
		(width 0.088646)
		(layer "In6.Cu")
		(net "M_C_CPU0_SA_CB<5>")
	)
	(arc
		(start 335.91246 -258.313428)
		(mid 335.725262 -258.363571)
		(end 335.538064 -258.313428)
		(width 0.088646)
		(layer "In6.Cu")
		(net "M_C_CPU0_SA_CB<5>")
	)
	(arc
		(start 333.09306 -258.313428)
		(mid 332.905862 -258.363571)
		(end 332.718664 -258.313428)
		(width 0.088646)
		(layer "In6.Cu")
		(net "M_C_CPU0_SA_CB<5>")
	)
	(arc
		(start 343.901014 -259.127498)
		(mid 343.713816 -259.177641)
		(end 343.526618 -259.127498)
		(width 0.088646)
		(layer "In6.Cu")
		(net "M_C_CPU0_SA_CB<5>")
	)
	(arc
		(start 343.339166 -258.79552)
		(mid 343.261537 -258.517107)
		(end 343.056464 -258.313428)
		(width 0.088646)
		(layer "In6.Cu")
		(net "M_C_CPU0_SA_CB<5>")
	)
	(arc
		(start 334.598264 -258.313428)
		(mid 334.315562 -258.237686)
		(end 334.03286 -258.313428)
		(width 0.088646)
		(layer "In6.Cu")
		(net "M_C_CPU0_SA_CB<5>")
	)
	(arc
		(start 342.101932 -258.304792)
		(mid 341.825491 -258.237626)
		(end 341.55126 -258.313428)
		(width 0.088646)
		(layer "In6.Cu")
		(net "M_C_CPU0_SA_CB<5>")
	)
	(arc
		(start 332.718664 -258.313428)
		(mid 332.435962 -258.237686)
		(end 332.15326 -258.313428)
		(width 0.088646)
		(layer "In6.Cu")
		(net "M_C_CPU0_SA_CB<5>")
	)
	(arc
		(start 335.538064 -258.313428)
		(mid 335.255362 -258.237686)
		(end 334.97266 -258.313428)
		(width 0.088646)
		(layer "In6.Cu")
		(net "M_C_CPU0_SA_CB<5>")
	)
	(arc
		(start 337.79206 -258.313428)
		(mid 337.604862 -258.363571)
		(end 337.417664 -258.313428)
		(width 0.088646)
		(layer "In6.Cu")
		(net "M_C_CPU0_SA_CB<5>")
	)
	(arc
		(start 344.083894 -258.860544)
		(mid 344.025738 -259.010657)
		(end 343.909904 -259.122418)
		(width 0.088646)
		(layer "In6.Cu")
		(net "M_C_CPU0_SA_CB<5>")
	)
	(segment
		(start 278.711914 -272.966688)
		(end 277.342854 -272.966688)
		(width 0.20066)
		(layer "F.Cu")
		(net "M_C_CPU0_SA_CB<4>")
	)
	(segment
		(start 343.243916 -259.616702)
		(end 343.243662 -259.616956)
		(width 0.20066)
		(layer "F.Cu")
		(net "M_C_CPU0_SA_CB<4>")
	)
	(segment
		(start 272.741136 -273.205448)
		(end 272.502376 -272.966688)
		(width 0.20066)
		(layer "F.Cu")
		(net "M_C_CPU0_SA_CB<4>")
	)
	(segment
		(start 277.342854 -272.966688)
		(end 276.917912 -272.541746)
		(width 0.20066)
		(layer "F.Cu")
		(net "M_C_CPU0_SA_CB<4>")
	)
	(segment
		(start 273.37258 -273.032728)
		(end 273.19986 -273.205448)
		(width 0.20066)
		(layer "F.Cu")
		(net "M_C_CPU0_SA_CB<4>")
	)
	(segment
		(start 276.538944 -272.541746)
		(end 276.469094 -272.541746)
		(width 0.101854)
		(layer "F.Cu")
		(net "M_C_CPU0_SA_CB<4>")
	)
	(segment
		(start 272.502376 -272.966688)
		(end 271.168114 -272.966688)
		(width 0.20066)
		(layer "F.Cu")
		(net "M_C_CPU0_SA_CB<4>")
	)
	(segment
		(start 276.917912 -272.541746)
		(end 276.538944 -272.541746)
		(width 0.20066)
		(layer "F.Cu")
		(net "M_C_CPU0_SA_CB<4>")
	)
	(segment
		(start 273.574002 -272.541746)
		(end 273.37258 -272.743168)
		(width 0.20066)
		(layer "F.Cu")
		(net "M_C_CPU0_SA_CB<4>")
	)
	(segment
		(start 273.37258 -272.743168)
		(end 273.37258 -273.032728)
		(width 0.20066)
		(layer "F.Cu")
		(net "M_C_CPU0_SA_CB<4>")
	)
	(segment
		(start 274.40001 -272.541746)
		(end 274.026376 -272.541746)
		(width 0.101854)
		(layer "F.Cu")
		(net "M_C_CPU0_SA_CB<4>")
	)
	(segment
		(start 273.19986 -273.205448)
		(end 272.741136 -273.205448)
		(width 0.20066)
		(layer "F.Cu")
		(net "M_C_CPU0_SA_CB<4>")
	)
	(segment
		(start 343.243916 -259.081016)
		(end 343.243916 -259.616702)
		(width 0.20066)
		(layer "F.Cu")
		(net "M_C_CPU0_SA_CB<4>")
	)
	(segment
		(start 276.469094 -272.541746)
		(end 274.40001 -272.541746)
		(width 0.1016)
		(layer "F.Cu")
		(net "M_C_CPU0_SA_CB<4>")
	)
	(segment
		(start 279.816814 -272.966688)
		(end 278.711914 -272.966688)
		(width 0.20066)
		(layer "F.Cu")
		(net "M_C_CPU0_SA_CB<4>")
	)
	(segment
		(start 274.026376 -272.541746)
		(end 273.574002 -272.541746)
		(width 0.20066)
		(layer "F.Cu")
		(net "M_C_CPU0_SA_CB<4>")
	)
	(segment
		(start 342.678766 -259.181346)
		(end 342.586564 -259.127498)
		(width 0.088646)
		(layer "In6.Cu")
		(net "M_C_CPU0_SA_CB<4>")
	)
	(segment
		(start 301.527718 -263.776206)
		(end 301.124366 -263.776206)
		(width 0.18288)
		(layer "In6.Cu")
		(net "M_C_CPU0_SA_CB<4>")
	)
	(segment
		(start 312.642758 -262.302752)
		(end 312.482738 -262.142732)
		(width 0.18288)
		(layer "In6.Cu")
		(net "M_C_CPU0_SA_CB<4>")
	)
	(segment
		(start 332.369414 -259.171694)
		(end 331.825854 -259.171694)
		(width 0.088646)
		(layer "In6.Cu")
		(net "M_C_CPU0_SA_CB<4>")
	)
	(segment
		(start 282.902152 -270.842486)
		(end 280.77795 -272.966688)
		(width 0.18288)
		(layer "In6.Cu")
		(net "M_C_CPU0_SA_CB<4>")
	)
	(segment
		(start 290.185094 -267.670026)
		(end 289.372294 -268.482826)
		(width 0.18288)
		(layer "In6.Cu")
		(net "M_C_CPU0_SA_CB<4>")
	)
	(segment
		(start 306.999894 -263.502648)
		(end 303.457102 -263.502648)
		(width 0.18288)
		(layer "In6.Cu")
		(net "M_C_CPU0_SA_CB<4>")
	)
	(segment
		(start 294.132762 -264.890758)
		(end 293.181786 -265.841734)
		(width 0.18288)
		(layer "In6.Cu")
		(net "M_C_CPU0_SA_CB<4>")
	)
	(segment
		(start 312.482738 -262.142732)
		(end 312.482738 -261.836662)
		(width 0.18288)
		(layer "In6.Cu")
		(net "M_C_CPU0_SA_CB<4>")
	)
	(segment
		(start 309.628794 -262.600948)
		(end 308.155594 -264.074148)
		(width 0.18288)
		(layer "In6.Cu")
		(net "M_C_CPU0_SA_CB<4>")
	)
	(segment
		(start 312.012076 -261.676642)
		(end 311.08777 -262.600948)
		(width 0.18288)
		(layer "In6.Cu")
		(net "M_C_CPU0_SA_CB<4>")
	)
	(segment
		(start 313.176158 -261.836662)
		(end 313.176158 -262.142732)
		(width 0.18288)
		(layer "In6.Cu")
		(net "M_C_CPU0_SA_CB<4>")
	)
	(segment
		(start 311.08777 -262.600948)
		(end 309.628794 -262.600948)
		(width 0.18288)
		(layer "In6.Cu")
		(net "M_C_CPU0_SA_CB<4>")
	)
	(segment
		(start 295.428162 -264.890758)
		(end 294.132762 -264.890758)
		(width 0.18288)
		(layer "In6.Cu")
		(net "M_C_CPU0_SA_CB<4>")
	)
	(segment
		(start 342.031828 -259.121402)
		(end 342.021414 -259.127498)
		(width 0.088646)
		(layer "In6.Cu")
		(net "M_C_CPU0_SA_CB<4>")
	)
	(segment
		(start 292.166294 -265.638026)
		(end 291.276024 -265.638026)
		(width 0.18288)
		(layer "In6.Cu")
		(net "M_C_CPU0_SA_CB<4>")
	)
	(segment
		(start 314.885832 -261.676642)
		(end 313.336178 -261.676642)
		(width 0.18288)
		(layer "In6.Cu")
		(net "M_C_CPU0_SA_CB<4>")
	)
	(segment
		(start 338.272374 -259.121402)
		(end 338.26196 -259.127498)
		(width 0.088646)
		(layer "In6.Cu")
		(net "M_C_CPU0_SA_CB<4>")
	)
	(segment
		(start 292.370002 -265.841734)
		(end 292.166294 -265.638026)
		(width 0.18288)
		(layer "In6.Cu")
		(net "M_C_CPU0_SA_CB<4>")
	)
	(segment
		(start 313.016138 -262.302752)
		(end 312.642758 -262.302752)
		(width 0.18288)
		(layer "In6.Cu")
		(net "M_C_CPU0_SA_CB<4>")
	)
	(segment
		(start 293.181786 -265.841734)
		(end 292.370002 -265.841734)
		(width 0.18288)
		(layer "In6.Cu")
		(net "M_C_CPU0_SA_CB<4>")
	)
	(segment
		(start 340.156546 -259.118862)
		(end 340.141814 -259.127498)
		(width 0.088646)
		(layer "In6.Cu")
		(net "M_C_CPU0_SA_CB<4>")
	)
	(segment
		(start 301.792386 -264.040874)
		(end 301.527718 -263.776206)
		(width 0.18288)
		(layer "In6.Cu")
		(net "M_C_CPU0_SA_CB<4>")
	)
	(segment
		(start 329.05446 -259.759704)
		(end 325.9455 -261.047484)
		(width 0.18288)
		(layer "In6.Cu")
		(net "M_C_CPU0_SA_CB<4>")
	)
	(segment
		(start 307.571394 -264.074148)
		(end 306.999894 -263.502648)
		(width 0.18288)
		(layer "In6.Cu")
		(net "M_C_CPU0_SA_CB<4>")
	)
	(segment
		(start 313.176158 -262.142732)
		(end 313.016138 -262.302752)
		(width 0.18288)
		(layer "In6.Cu")
		(net "M_C_CPU0_SA_CB<4>")
	)
	(segment
		(start 300.859698 -264.040874)
		(end 296.278046 -264.040874)
		(width 0.18288)
		(layer "In6.Cu")
		(net "M_C_CPU0_SA_CB<4>")
	)
	(segment
		(start 312.482738 -261.836662)
		(end 312.322718 -261.676642)
		(width 0.18288)
		(layer "In6.Cu")
		(net "M_C_CPU0_SA_CB<4>")
	)
	(segment
		(start 315.51499 -261.047484)
		(end 314.885832 -261.676642)
		(width 0.18288)
		(layer "In6.Cu")
		(net "M_C_CPU0_SA_CB<4>")
	)
	(segment
		(start 302.918876 -264.040874)
		(end 301.792386 -264.040874)
		(width 0.18288)
		(layer "In6.Cu")
		(net "M_C_CPU0_SA_CB<4>")
	)
	(segment
		(start 343.243662 -259.616956)
		(end 342.678766 -259.181346)
		(width 0.088646)
		(layer "In6.Cu")
		(net "M_C_CPU0_SA_CB<4>")
	)
	(segment
		(start 331.825854 -259.171694)
		(end 331.237844 -259.759704)
		(width 0.088646)
		(layer "In6.Cu")
		(net "M_C_CPU0_SA_CB<4>")
	)
	(segment
		(start 296.278046 -264.040874)
		(end 295.428162 -264.890758)
		(width 0.18288)
		(layer "In6.Cu")
		(net "M_C_CPU0_SA_CB<4>")
	)
	(segment
		(start 301.124366 -263.776206)
		(end 300.859698 -264.040874)
		(width 0.18288)
		(layer "In6.Cu")
		(net "M_C_CPU0_SA_CB<4>")
	)
	(segment
		(start 331.028802 -259.759704)
		(end 329.05446 -259.759704)
		(width 0.18288)
		(layer "In6.Cu")
		(net "M_C_CPU0_SA_CB<4>")
	)
	(segment
		(start 287.924494 -269.321026)
		(end 287.010094 -269.321026)
		(width 0.18288)
		(layer "In6.Cu")
		(net "M_C_CPU0_SA_CB<4>")
	)
	(segment
		(start 303.457102 -263.502648)
		(end 302.918876 -264.040874)
		(width 0.18288)
		(layer "In6.Cu")
		(net "M_C_CPU0_SA_CB<4>")
	)
	(segment
		(start 325.9455 -261.047484)
		(end 315.51499 -261.047484)
		(width 0.18288)
		(layer "In6.Cu")
		(net "M_C_CPU0_SA_CB<4>")
	)
	(segment
		(start 291.276024 -265.638026)
		(end 290.185094 -266.728956)
		(width 0.18288)
		(layer "In6.Cu")
		(net "M_C_CPU0_SA_CB<4>")
	)
	(segment
		(start 313.336178 -261.676642)
		(end 313.176158 -261.836662)
		(width 0.18288)
		(layer "In6.Cu")
		(net "M_C_CPU0_SA_CB<4>")
	)
	(segment
		(start 287.010094 -269.321026)
		(end 285.488634 -270.842486)
		(width 0.18288)
		(layer "In6.Cu")
		(net "M_C_CPU0_SA_CB<4>")
	)
	(segment
		(start 341.096346 -259.118862)
		(end 341.081614 -259.127498)
		(width 0.088646)
		(layer "In6.Cu")
		(net "M_C_CPU0_SA_CB<4>")
	)
	(segment
		(start 289.372294 -268.482826)
		(end 288.762694 -268.482826)
		(width 0.18288)
		(layer "In6.Cu")
		(net "M_C_CPU0_SA_CB<4>")
	)
	(segment
		(start 312.322718 -261.676642)
		(end 312.012076 -261.676642)
		(width 0.18288)
		(layer "In6.Cu")
		(net "M_C_CPU0_SA_CB<4>")
	)
	(segment
		(start 290.185094 -266.728956)
		(end 290.185094 -267.670026)
		(width 0.18288)
		(layer "In6.Cu")
		(net "M_C_CPU0_SA_CB<4>")
	)
	(segment
		(start 280.77795 -272.966688)
		(end 279.816814 -272.966688)
		(width 0.18288)
		(layer "In6.Cu")
		(net "M_C_CPU0_SA_CB<4>")
	)
	(segment
		(start 331.237844 -259.759704)
		(end 331.028802 -259.759704)
		(width 0.088646)
		(layer "In6.Cu")
		(net "M_C_CPU0_SA_CB<4>")
	)
	(segment
		(start 288.762694 -268.482826)
		(end 287.924494 -269.321026)
		(width 0.18288)
		(layer "In6.Cu")
		(net "M_C_CPU0_SA_CB<4>")
	)
	(segment
		(start 308.155594 -264.074148)
		(end 307.571394 -264.074148)
		(width 0.18288)
		(layer "In6.Cu")
		(net "M_C_CPU0_SA_CB<4>")
	)
	(segment
		(start 285.488634 -270.842486)
		(end 282.902152 -270.842486)
		(width 0.18288)
		(layer "In6.Cu")
		(net "M_C_CPU0_SA_CB<4>")
	)
	(arc
		(start 341.647018 -259.127498)
		(mid 341.372819 -259.051663)
		(end 341.096346 -259.118862)
		(width 0.088646)
		(layer "In6.Cu")
		(net "M_C_CPU0_SA_CB<4>")
	)
	(arc
		(start 338.26196 -259.127498)
		(mid 338.074762 -259.177641)
		(end 337.887564 -259.127498)
		(width 0.088646)
		(layer "In6.Cu")
		(net "M_C_CPU0_SA_CB<4>")
	)
	(arc
		(start 341.081614 -259.127498)
		(mid 340.894416 -259.177641)
		(end 340.707218 -259.127498)
		(width 0.088646)
		(layer "In6.Cu")
		(net "M_C_CPU0_SA_CB<4>")
	)
	(arc
		(start 336.38236 -259.127498)
		(mid 336.195162 -259.177641)
		(end 336.007964 -259.127498)
		(width 0.088646)
		(layer "In6.Cu")
		(net "M_C_CPU0_SA_CB<4>")
	)
	(arc
		(start 339.202014 -259.127498)
		(mid 339.014816 -259.177641)
		(end 338.827618 -259.127498)
		(width 0.088646)
		(layer "In6.Cu")
		(net "M_C_CPU0_SA_CB<4>")
	)
	(arc
		(start 335.44256 -259.127498)
		(mid 335.255362 -259.177641)
		(end 335.068164 -259.127498)
		(width 0.088646)
		(layer "In6.Cu")
		(net "M_C_CPU0_SA_CB<4>")
	)
	(arc
		(start 339.767418 -259.127498)
		(mid 339.484716 -259.051722)
		(end 339.202014 -259.127498)
		(width 0.088646)
		(layer "In6.Cu")
		(net "M_C_CPU0_SA_CB<4>")
	)
	(arc
		(start 334.128364 -259.127498)
		(mid 333.845662 -259.051722)
		(end 333.56296 -259.127498)
		(width 0.088646)
		(layer "In6.Cu")
		(net "M_C_CPU0_SA_CB<4>")
	)
	(arc
		(start 342.586564 -259.127498)
		(mid 342.310005 -259.051755)
		(end 342.031828 -259.121402)
		(width 0.088646)
		(layer "In6.Cu")
		(net "M_C_CPU0_SA_CB<4>")
	)
	(arc
		(start 337.32216 -259.127498)
		(mid 337.134962 -259.177641)
		(end 336.947764 -259.127498)
		(width 0.088646)
		(layer "In6.Cu")
		(net "M_C_CPU0_SA_CB<4>")
	)
	(arc
		(start 334.50276 -259.127498)
		(mid 334.315562 -259.177641)
		(end 334.128364 -259.127498)
		(width 0.088646)
		(layer "In6.Cu")
		(net "M_C_CPU0_SA_CB<4>")
	)
	(arc
		(start 335.068164 -259.127498)
		(mid 334.785462 -259.051722)
		(end 334.50276 -259.127498)
		(width 0.088646)
		(layer "In6.Cu")
		(net "M_C_CPU0_SA_CB<4>")
	)
	(arc
		(start 342.021414 -259.127498)
		(mid 341.834216 -259.177641)
		(end 341.647018 -259.127498)
		(width 0.088646)
		(layer "In6.Cu")
		(net "M_C_CPU0_SA_CB<4>")
	)
	(arc
		(start 337.887564 -259.127498)
		(mid 337.604862 -259.051722)
		(end 337.32216 -259.127498)
		(width 0.088646)
		(layer "In6.Cu")
		(net "M_C_CPU0_SA_CB<4>")
	)
	(arc
		(start 332.62316 -259.127498)
		(mid 332.500206 -259.17209)
		(end 332.369414 -259.171694)
		(width 0.088646)
		(layer "In6.Cu")
		(net "M_C_CPU0_SA_CB<4>")
	)
	(arc
		(start 340.707218 -259.127498)
		(mid 340.433019 -259.051663)
		(end 340.156546 -259.118862)
		(width 0.088646)
		(layer "In6.Cu")
		(net "M_C_CPU0_SA_CB<4>")
	)
	(arc
		(start 333.56296 -259.127498)
		(mid 333.375762 -259.177641)
		(end 333.188564 -259.127498)
		(width 0.088646)
		(layer "In6.Cu")
		(net "M_C_CPU0_SA_CB<4>")
	)
	(arc
		(start 336.007964 -259.127498)
		(mid 335.725262 -259.051722)
		(end 335.44256 -259.127498)
		(width 0.088646)
		(layer "In6.Cu")
		(net "M_C_CPU0_SA_CB<4>")
	)
	(arc
		(start 340.141814 -259.127498)
		(mid 339.954616 -259.177641)
		(end 339.767418 -259.127498)
		(width 0.088646)
		(layer "In6.Cu")
		(net "M_C_CPU0_SA_CB<4>")
	)
	(arc
		(start 336.947764 -259.127498)
		(mid 336.665062 -259.051722)
		(end 336.38236 -259.127498)
		(width 0.088646)
		(layer "In6.Cu")
		(net "M_C_CPU0_SA_CB<4>")
	)
	(arc
		(start 338.827618 -259.127498)
		(mid 338.550805 -259.051628)
		(end 338.272374 -259.121402)
		(width 0.088646)
		(layer "In6.Cu")
		(net "M_C_CPU0_SA_CB<4>")
	)
	(arc
		(start 333.188564 -259.127498)
		(mid 332.905862 -259.051722)
		(end 332.62316 -259.127498)
		(width 0.088646)
		(layer "In6.Cu")
		(net "M_C_CPU0_SA_CB<4>")
	)
	(segment
		(start 277.091394 -276.64918)
		(end 277.091394 -276.492716)
		(width 0.20066)
		(layer "F.Cu")
		(net "M_C_CPU0_SA_CB<3>")
	)
	(segment
		(start 276.96541 -276.366732)
		(end 275.268182 -276.366732)
		(width 0.20066)
		(layer "F.Cu")
		(net "M_C_CPU0_SA_CB<3>")
	)
	(segment
		(start 277.460964 -276.791674)
		(end 277.233888 -276.791674)
		(width 0.20066)
		(layer "F.Cu")
		(net "M_C_CPU0_SA_CB<3>")
	)
	(segment
		(start 280.606246 -276.43963)
		(end 280.606246 -276.642576)
		(width 0.20066)
		(layer "F.Cu")
		(net "M_C_CPU0_SA_CB<3>")
	)
	(segment
		(start 281.154886 -276.23897)
		(end 280.806906 -276.23897)
		(width 0.20066)
		(layer "F.Cu")
		(net "M_C_CPU0_SA_CB<3>")
	)
	(segment
		(start 281.99588 -276.366732)
		(end 281.882342 -276.48027)
		(width 0.20066)
		(layer "F.Cu")
		(net "M_C_CPU0_SA_CB<3>")
	)
	(segment
		(start 277.233888 -276.791674)
		(end 277.091394 -276.64918)
		(width 0.20066)
		(layer "F.Cu")
		(net "M_C_CPU0_SA_CB<3>")
	)
	(segment
		(start 345.123516 -260.708902)
		(end 345.123516 -261.244588)
		(width 0.20066)
		(layer "F.Cu")
		(net "M_C_CPU0_SA_CB<3>")
	)
	(segment
		(start 280.606246 -276.642576)
		(end 280.457148 -276.791674)
		(width 0.20066)
		(layer "F.Cu")
		(net "M_C_CPU0_SA_CB<3>")
	)
	(segment
		(start 282.811982 -276.366732)
		(end 281.99588 -276.366732)
		(width 0.20066)
		(layer "F.Cu")
		(net "M_C_CPU0_SA_CB<3>")
	)
	(segment
		(start 281.396186 -276.48027)
		(end 281.154886 -276.23897)
		(width 0.20066)
		(layer "F.Cu")
		(net "M_C_CPU0_SA_CB<3>")
	)
	(segment
		(start 277.091394 -276.492716)
		(end 276.96541 -276.366732)
		(width 0.20066)
		(layer "F.Cu")
		(net "M_C_CPU0_SA_CB<3>")
	)
	(segment
		(start 279.912826 -276.791674)
		(end 277.839932 -276.791674)
		(width 0.1016)
		(layer "F.Cu")
		(net "M_C_CPU0_SA_CB<3>")
	)
	(segment
		(start 280.457148 -276.791674)
		(end 279.985724 -276.791674)
		(width 0.20066)
		(layer "F.Cu")
		(net "M_C_CPU0_SA_CB<3>")
	)
	(segment
		(start 280.806906 -276.23897)
		(end 280.606246 -276.43963)
		(width 0.20066)
		(layer "F.Cu")
		(net "M_C_CPU0_SA_CB<3>")
	)
	(segment
		(start 277.839932 -276.791674)
		(end 277.460964 -276.791674)
		(width 0.101854)
		(layer "F.Cu")
		(net "M_C_CPU0_SA_CB<3>")
	)
	(segment
		(start 283.916882 -276.366732)
		(end 282.811982 -276.366732)
		(width 0.20066)
		(layer "F.Cu")
		(net "M_C_CPU0_SA_CB<3>")
	)
	(segment
		(start 281.882342 -276.48027)
		(end 281.396186 -276.48027)
		(width 0.20066)
		(layer "F.Cu")
		(net "M_C_CPU0_SA_CB<3>")
	)
	(segment
		(start 345.123516 -261.244588)
		(end 345.123262 -261.244842)
		(width 0.20066)
		(layer "F.Cu")
		(net "M_C_CPU0_SA_CB<3>")
	)
	(segment
		(start 279.985724 -276.791674)
		(end 279.912826 -276.791674)
		(width 0.101854)
		(layer "F.Cu")
		(net "M_C_CPU0_SA_CB<3>")
	)
	(segment
		(start 313.772804 -267.424916)
		(end 312.341006 -268.856714)
		(width 0.18288)
		(layer "In6.Cu")
		(net "M_C_CPU0_SA_CB<3>")
	)
	(segment
		(start 306.840382 -268.907514)
		(end 305.871118 -268.907514)
		(width 0.18288)
		(layer "In6.Cu")
		(net "M_C_CPU0_SA_CB<3>")
	)
	(segment
		(start 305.688238 -269.610332)
		(end 305.505358 -269.793212)
		(width 0.18288)
		(layer "In6.Cu")
		(net "M_C_CPU0_SA_CB<3>")
	)
	(segment
		(start 309.193946 -268.861286)
		(end 308.647592 -268.861286)
		(width 0.18288)
		(layer "In6.Cu")
		(net "M_C_CPU0_SA_CB<3>")
	)
	(segment
		(start 300.926754 -270.157448)
		(end 300.926754 -269.851124)
		(width 0.18288)
		(layer "In6.Cu")
		(net "M_C_CPU0_SA_CB<3>")
	)
	(segment
		(start 300.052994 -269.668244)
		(end 299.730414 -269.990824)
		(width 0.18288)
		(layer "In6.Cu")
		(net "M_C_CPU0_SA_CB<3>")
	)
	(segment
		(start 343.915746 -261.742936)
		(end 343.901014 -261.7343)
		(width 0.088646)
		(layer "In6.Cu")
		(net "M_C_CPU0_SA_CB<3>")
	)
	(segment
		(start 285.867094 -275.721826)
		(end 284.561788 -275.721826)
		(width 0.18288)
		(layer "In6.Cu")
		(net "M_C_CPU0_SA_CB<3>")
	)
	(segment
		(start 301.434754 -270.340328)
		(end 301.109634 -270.340328)
		(width 0.18288)
		(layer "In6.Cu")
		(net "M_C_CPU0_SA_CB<3>")
	)
	(segment
		(start 301.617634 -269.851124)
		(end 301.617634 -270.157448)
		(width 0.18288)
		(layer "In6.Cu")
		(net "M_C_CPU0_SA_CB<3>")
	)
	(segment
		(start 308.647592 -268.861286)
		(end 308.464712 -269.044166)
		(width 0.18288)
		(layer "In6.Cu")
		(net "M_C_CPU0_SA_CB<3>")
	)
	(segment
		(start 331.625956 -262.510016)
		(end 331.23886 -262.897112)
		(width 0.088646)
		(layer "In6.Cu")
		(net "M_C_CPU0_SA_CB<3>")
	)
	(segment
		(start 288.473134 -274.215606)
		(end 287.779714 -274.909026)
		(width 0.18288)
		(layer "In6.Cu")
		(net "M_C_CPU0_SA_CB<3>")
	)
	(segment
		(start 287.779714 -274.909026)
		(end 286.679894 -274.909026)
		(width 0.18288)
		(layer "In6.Cu")
		(net "M_C_CPU0_SA_CB<3>")
	)
	(segment
		(start 308.464712 -269.578074)
		(end 308.297072 -269.745714)
		(width 0.18288)
		(layer "In6.Cu")
		(net "M_C_CPU0_SA_CB<3>")
	)
	(segment
		(start 305.180238 -269.793212)
		(end 304.997358 -269.610332)
		(width 0.18288)
		(layer "In6.Cu")
		(net "M_C_CPU0_SA_CB<3>")
	)
	(segment
		(start 301.617634 -270.157448)
		(end 301.434754 -270.340328)
		(width 0.18288)
		(layer "In6.Cu")
		(net "M_C_CPU0_SA_CB<3>")
	)
	(segment
		(start 309.782718 -268.272514)
		(end 309.193946 -268.861286)
		(width 0.18288)
		(layer "In6.Cu")
		(net "M_C_CPU0_SA_CB<3>")
	)
	(segment
		(start 330.598272 -262.897112)
		(end 329.607926 -262.897112)
		(width 0.18288)
		(layer "In6.Cu")
		(net "M_C_CPU0_SA_CB<3>")
	)
	(segment
		(start 341.096346 -261.742936)
		(end 341.081614 -261.7343)
		(width 0.088646)
		(layer "In6.Cu")
		(net "M_C_CPU0_SA_CB<3>")
	)
	(segment
		(start 300.926754 -269.851124)
		(end 300.743874 -269.668244)
		(width 0.18288)
		(layer "In6.Cu")
		(net "M_C_CPU0_SA_CB<3>")
	)
	(segment
		(start 339.212174 -261.740396)
		(end 339.20176 -261.7343)
		(width 0.088646)
		(layer "In6.Cu")
		(net "M_C_CPU0_SA_CB<3>")
	)
	(segment
		(start 286.679894 -274.909026)
		(end 285.867094 -275.721826)
		(width 0.18288)
		(layer "In6.Cu")
		(net "M_C_CPU0_SA_CB<3>")
	)
	(segment
		(start 289.456114 -274.215606)
		(end 288.473134 -274.215606)
		(width 0.18288)
		(layer "In6.Cu")
		(net "M_C_CPU0_SA_CB<3>")
	)
	(segment
		(start 305.871118 -268.907514)
		(end 305.688238 -269.090394)
		(width 0.18288)
		(layer "In6.Cu")
		(net "M_C_CPU0_SA_CB<3>")
	)
	(segment
		(start 331.625956 -262.03783)
		(end 331.625956 -262.510016)
		(width 0.088646)
		(layer "In6.Cu")
		(net "M_C_CPU0_SA_CB<3>")
	)
	(segment
		(start 336.392774 -261.740396)
		(end 336.38236 -261.7343)
		(width 0.088646)
		(layer "In6.Cu")
		(net "M_C_CPU0_SA_CB<3>")
	)
	(segment
		(start 314.424568 -267.424916)
		(end 313.772804 -267.424916)
		(width 0.18288)
		(layer "In6.Cu")
		(net "M_C_CPU0_SA_CB<3>")
	)
	(segment
		(start 308.297072 -269.745714)
		(end 307.678582 -269.745714)
		(width 0.18288)
		(layer "In6.Cu")
		(net "M_C_CPU0_SA_CB<3>")
	)
	(segment
		(start 301.800514 -269.668244)
		(end 301.617634 -269.851124)
		(width 0.18288)
		(layer "In6.Cu")
		(net "M_C_CPU0_SA_CB<3>")
	)
	(segment
		(start 304.814478 -268.907514)
		(end 304.123598 -268.907514)
		(width 0.18288)
		(layer "In6.Cu")
		(net "M_C_CPU0_SA_CB<3>")
	)
	(segment
		(start 299.730414 -269.990824)
		(end 298.745148 -269.990824)
		(width 0.18288)
		(layer "In6.Cu")
		(net "M_C_CPU0_SA_CB<3>")
	)
	(segment
		(start 298.745148 -269.990824)
		(end 296.194734 -272.541238)
		(width 0.18288)
		(layer "In6.Cu")
		(net "M_C_CPU0_SA_CB<3>")
	)
	(segment
		(start 304.997358 -269.090394)
		(end 304.814478 -268.907514)
		(width 0.18288)
		(layer "In6.Cu")
		(net "M_C_CPU0_SA_CB<3>")
	)
	(segment
		(start 308.464712 -269.044166)
		(end 308.464712 -269.578074)
		(width 0.18288)
		(layer "In6.Cu")
		(net "M_C_CPU0_SA_CB<3>")
	)
	(segment
		(start 337.332828 -261.740396)
		(end 337.322414 -261.7343)
		(width 0.088646)
		(layer "In6.Cu")
		(net "M_C_CPU0_SA_CB<3>")
	)
	(segment
		(start 311.190894 -268.856714)
		(end 310.606694 -268.272514)
		(width 0.18288)
		(layer "In6.Cu")
		(net "M_C_CPU0_SA_CB<3>")
	)
	(segment
		(start 342.036146 -261.742936)
		(end 342.021414 -261.7343)
		(width 0.088646)
		(layer "In6.Cu")
		(net "M_C_CPU0_SA_CB<3>")
	)
	(segment
		(start 296.194734 -272.541238)
		(end 291.130482 -272.541238)
		(width 0.18288)
		(layer "In6.Cu")
		(net "M_C_CPU0_SA_CB<3>")
	)
	(segment
		(start 303.362868 -269.668244)
		(end 301.800514 -269.668244)
		(width 0.18288)
		(layer "In6.Cu")
		(net "M_C_CPU0_SA_CB<3>")
	)
	(segment
		(start 307.678582 -269.745714)
		(end 306.840382 -268.907514)
		(width 0.18288)
		(layer "In6.Cu")
		(net "M_C_CPU0_SA_CB<3>")
	)
	(segment
		(start 342.975946 -261.742936)
		(end 342.961214 -261.7343)
		(width 0.088646)
		(layer "In6.Cu")
		(net "M_C_CPU0_SA_CB<3>")
	)
	(segment
		(start 320.759836 -264.21588)
		(end 315.423296 -266.426188)
		(width 0.18288)
		(layer "In6.Cu")
		(net "M_C_CPU0_SA_CB<3>")
	)
	(segment
		(start 326.424036 -264.21588)
		(end 320.759836 -264.21588)
		(width 0.18288)
		(layer "In6.Cu")
		(net "M_C_CPU0_SA_CB<3>")
	)
	(segment
		(start 331.853794 -261.809992)
		(end 331.625956 -262.03783)
		(width 0.088646)
		(layer "In6.Cu")
		(net "M_C_CPU0_SA_CB<3>")
	)
	(segment
		(start 300.743874 -269.668244)
		(end 300.052994 -269.668244)
		(width 0.18288)
		(layer "In6.Cu")
		(net "M_C_CPU0_SA_CB<3>")
	)
	(segment
		(start 340.156546 -261.742936)
		(end 340.141814 -261.7343)
		(width 0.088646)
		(layer "In6.Cu")
		(net "M_C_CPU0_SA_CB<3>")
	)
	(segment
		(start 291.130482 -272.541238)
		(end 289.456114 -274.215606)
		(width 0.18288)
		(layer "In6.Cu")
		(net "M_C_CPU0_SA_CB<3>")
	)
	(segment
		(start 305.688238 -269.090394)
		(end 305.688238 -269.610332)
		(width 0.18288)
		(layer "In6.Cu")
		(net "M_C_CPU0_SA_CB<3>")
	)
	(segment
		(start 331.966062 -261.809992)
		(end 331.853794 -261.809992)
		(width 0.088646)
		(layer "In6.Cu")
		(net "M_C_CPU0_SA_CB<3>")
	)
	(segment
		(start 304.997358 -269.610332)
		(end 304.997358 -269.090394)
		(width 0.18288)
		(layer "In6.Cu")
		(net "M_C_CPU0_SA_CB<3>")
	)
	(segment
		(start 310.606694 -268.272514)
		(end 309.782718 -268.272514)
		(width 0.18288)
		(layer "In6.Cu")
		(net "M_C_CPU0_SA_CB<3>")
	)
	(segment
		(start 304.123598 -268.907514)
		(end 303.362868 -269.668244)
		(width 0.18288)
		(layer "In6.Cu")
		(net "M_C_CPU0_SA_CB<3>")
	)
	(segment
		(start 301.109634 -270.340328)
		(end 300.926754 -270.157448)
		(width 0.18288)
		(layer "In6.Cu")
		(net "M_C_CPU0_SA_CB<3>")
	)
	(segment
		(start 305.505358 -269.793212)
		(end 305.180238 -269.793212)
		(width 0.18288)
		(layer "In6.Cu")
		(net "M_C_CPU0_SA_CB<3>")
	)
	(segment
		(start 329.607926 -262.897112)
		(end 326.424036 -264.21588)
		(width 0.18288)
		(layer "In6.Cu")
		(net "M_C_CPU0_SA_CB<3>")
	)
	(segment
		(start 331.23886 -262.897112)
		(end 330.598272 -262.897112)
		(width 0.088646)
		(layer "In6.Cu")
		(net "M_C_CPU0_SA_CB<3>")
	)
	(segment
		(start 312.341006 -268.856714)
		(end 311.190894 -268.856714)
		(width 0.18288)
		(layer "In6.Cu")
		(net "M_C_CPU0_SA_CB<3>")
	)
	(segment
		(start 284.561788 -275.721826)
		(end 283.916882 -276.366732)
		(width 0.18288)
		(layer "In6.Cu")
		(net "M_C_CPU0_SA_CB<3>")
	)
	(segment
		(start 315.423296 -266.426188)
		(end 314.424568 -267.424916)
		(width 0.18288)
		(layer "In6.Cu")
		(net "M_C_CPU0_SA_CB<3>")
	)
	(arc
		(start 343.526618 -261.7343)
		(mid 343.252419 -261.810135)
		(end 342.975946 -261.742936)
		(width 0.088646)
		(layer "In6.Cu")
		(net "M_C_CPU0_SA_CB<3>")
	)
	(arc
		(start 336.007964 -261.7343)
		(mid 335.725262 -261.810076)
		(end 335.44256 -261.7343)
		(width 0.088646)
		(layer "In6.Cu")
		(net "M_C_CPU0_SA_CB<3>")
	)
	(arc
		(start 342.586818 -261.7343)
		(mid 342.312619 -261.810135)
		(end 342.036146 -261.742936)
		(width 0.088646)
		(layer "In6.Cu")
		(net "M_C_CPU0_SA_CB<3>")
	)
	(arc
		(start 334.128364 -261.7343)
		(mid 333.845662 -261.810076)
		(end 333.56296 -261.7343)
		(width 0.088646)
		(layer "In6.Cu")
		(net "M_C_CPU0_SA_CB<3>")
	)
	(arc
		(start 333.56296 -261.7343)
		(mid 333.375762 -261.684157)
		(end 333.188564 -261.7343)
		(width 0.088646)
		(layer "In6.Cu")
		(net "M_C_CPU0_SA_CB<3>")
	)
	(arc
		(start 338.26196 -261.7343)
		(mid 338.074762 -261.684157)
		(end 337.887564 -261.7343)
		(width 0.088646)
		(layer "In6.Cu")
		(net "M_C_CPU0_SA_CB<3>")
	)
	(arc
		(start 339.20176 -261.7343)
		(mid 339.014562 -261.684157)
		(end 338.827364 -261.7343)
		(width 0.088646)
		(layer "In6.Cu")
		(net "M_C_CPU0_SA_CB<3>")
	)
	(arc
		(start 337.887564 -261.7343)
		(mid 337.611005 -261.810043)
		(end 337.332828 -261.740396)
		(width 0.088646)
		(layer "In6.Cu")
		(net "M_C_CPU0_SA_CB<3>")
	)
	(arc
		(start 338.827364 -261.7343)
		(mid 338.544662 -261.810076)
		(end 338.26196 -261.7343)
		(width 0.088646)
		(layer "In6.Cu")
		(net "M_C_CPU0_SA_CB<3>")
	)
	(arc
		(start 337.322414 -261.7343)
		(mid 337.135216 -261.684123)
		(end 336.948018 -261.7343)
		(width 0.088646)
		(layer "In6.Cu")
		(net "M_C_CPU0_SA_CB<3>")
	)
	(arc
		(start 344.466418 -261.7343)
		(mid 344.192219 -261.810135)
		(end 343.915746 -261.742936)
		(width 0.088646)
		(layer "In6.Cu")
		(net "M_C_CPU0_SA_CB<3>")
	)
	(arc
		(start 340.141814 -261.7343)
		(mid 339.954616 -261.684157)
		(end 339.767418 -261.7343)
		(width 0.088646)
		(layer "In6.Cu")
		(net "M_C_CPU0_SA_CB<3>")
	)
	(arc
		(start 332.248764 -261.7343)
		(mid 332.112395 -261.790742)
		(end 331.966062 -261.809992)
		(width 0.088646)
		(layer "In6.Cu")
		(net "M_C_CPU0_SA_CB<3>")
	)
	(arc
		(start 342.961214 -261.7343)
		(mid 342.774016 -261.684157)
		(end 342.586818 -261.7343)
		(width 0.088646)
		(layer "In6.Cu")
		(net "M_C_CPU0_SA_CB<3>")
	)
	(arc
		(start 339.767418 -261.7343)
		(mid 339.490605 -261.81017)
		(end 339.212174 -261.740396)
		(width 0.088646)
		(layer "In6.Cu")
		(net "M_C_CPU0_SA_CB<3>")
	)
	(arc
		(start 335.068164 -261.7343)
		(mid 334.785462 -261.810076)
		(end 334.50276 -261.7343)
		(width 0.088646)
		(layer "In6.Cu")
		(net "M_C_CPU0_SA_CB<3>")
	)
	(arc
		(start 335.44256 -261.7343)
		(mid 335.255362 -261.684157)
		(end 335.068164 -261.7343)
		(width 0.088646)
		(layer "In6.Cu")
		(net "M_C_CPU0_SA_CB<3>")
	)
	(arc
		(start 343.901014 -261.7343)
		(mid 343.713816 -261.684157)
		(end 343.526618 -261.7343)
		(width 0.088646)
		(layer "In6.Cu")
		(net "M_C_CPU0_SA_CB<3>")
	)
	(arc
		(start 336.948018 -261.7343)
		(mid 336.671205 -261.81017)
		(end 336.392774 -261.740396)
		(width 0.088646)
		(layer "In6.Cu")
		(net "M_C_CPU0_SA_CB<3>")
	)
	(arc
		(start 334.50276 -261.7343)
		(mid 334.315562 -261.684157)
		(end 334.128364 -261.7343)
		(width 0.088646)
		(layer "In6.Cu")
		(net "M_C_CPU0_SA_CB<3>")
	)
	(arc
		(start 336.38236 -261.7343)
		(mid 336.195162 -261.684157)
		(end 336.007964 -261.7343)
		(width 0.088646)
		(layer "In6.Cu")
		(net "M_C_CPU0_SA_CB<3>")
	)
	(arc
		(start 340.707218 -261.7343)
		(mid 340.433019 -261.810135)
		(end 340.156546 -261.742936)
		(width 0.088646)
		(layer "In6.Cu")
		(net "M_C_CPU0_SA_CB<3>")
	)
	(arc
		(start 342.021414 -261.7343)
		(mid 341.834216 -261.684157)
		(end 341.647018 -261.7343)
		(width 0.088646)
		(layer "In6.Cu")
		(net "M_C_CPU0_SA_CB<3>")
	)
	(arc
		(start 341.647018 -261.7343)
		(mid 341.372819 -261.810135)
		(end 341.096346 -261.742936)
		(width 0.088646)
		(layer "In6.Cu")
		(net "M_C_CPU0_SA_CB<3>")
	)
	(arc
		(start 345.123262 -261.244842)
		(mid 344.809085 -261.508688)
		(end 344.466418 -261.7343)
		(width 0.088646)
		(layer "In6.Cu")
		(net "M_C_CPU0_SA_CB<3>")
	)
	(arc
		(start 332.62316 -261.7343)
		(mid 332.435962 -261.684157)
		(end 332.248764 -261.7343)
		(width 0.088646)
		(layer "In6.Cu")
		(net "M_C_CPU0_SA_CB<3>")
	)
	(arc
		(start 341.081614 -261.7343)
		(mid 340.894416 -261.684157)
		(end 340.707218 -261.7343)
		(width 0.088646)
		(layer "In6.Cu")
		(net "M_C_CPU0_SA_CB<3>")
	)
	(arc
		(start 333.188564 -261.7343)
		(mid 332.905862 -261.810076)
		(end 332.62316 -261.7343)
		(width 0.088646)
		(layer "In6.Cu")
		(net "M_C_CPU0_SA_CB<3>")
	)
	(segment
		(start 277.456138 -277.641812)
		(end 276.840188 -277.641812)
		(width 0.20066)
		(layer "F.Cu")
		(net "M_C_CPU0_SA_CB<2>")
	)
	(segment
		(start 276.415246 -278.066754)
		(end 275.268182 -278.066754)
		(width 0.20066)
		(layer "F.Cu")
		(net "M_C_CPU0_SA_CB<2>")
	)
	(segment
		(start 280.521918 -277.641812)
		(end 279.984708 -277.641812)
		(width 0.20066)
		(layer "F.Cu")
		(net "M_C_CPU0_SA_CB<2>")
	)
	(segment
		(start 280.887424 -278.30907)
		(end 280.689558 -278.111204)
		(width 0.20066)
		(layer "F.Cu")
		(net "M_C_CPU0_SA_CB<2>")
	)
	(segment
		(start 281.497278 -278.066754)
		(end 281.254962 -278.30907)
		(width 0.20066)
		(layer "F.Cu")
		(net "M_C_CPU0_SA_CB<2>")
	)
	(segment
		(start 280.689558 -278.111204)
		(end 280.689558 -277.809452)
		(width 0.20066)
		(layer "F.Cu")
		(net "M_C_CPU0_SA_CB<2>")
	)
	(segment
		(start 282.811982 -278.066754)
		(end 281.497278 -278.066754)
		(width 0.20066)
		(layer "F.Cu")
		(net "M_C_CPU0_SA_CB<2>")
	)
	(segment
		(start 283.916882 -278.066754)
		(end 282.811982 -278.066754)
		(width 0.20066)
		(layer "F.Cu")
		(net "M_C_CPU0_SA_CB<2>")
	)
	(segment
		(start 344.653362 -262.058404)
		(end 344.653616 -262.058658)
		(width 0.20066)
		(layer "F.Cu")
		(net "M_C_CPU0_SA_CB<2>")
	)
	(segment
		(start 281.254962 -278.30907)
		(end 280.887424 -278.30907)
		(width 0.20066)
		(layer "F.Cu")
		(net "M_C_CPU0_SA_CB<2>")
	)
	(segment
		(start 276.840188 -277.641812)
		(end 276.415246 -278.066754)
		(width 0.20066)
		(layer "F.Cu")
		(net "M_C_CPU0_SA_CB<2>")
	)
	(segment
		(start 279.984708 -277.641812)
		(end 279.950672 -277.641812)
		(width 0.101854)
		(layer "F.Cu")
		(net "M_C_CPU0_SA_CB<2>")
	)
	(segment
		(start 280.689558 -277.809452)
		(end 280.521918 -277.641812)
		(width 0.20066)
		(layer "F.Cu")
		(net "M_C_CPU0_SA_CB<2>")
	)
	(segment
		(start 277.852886 -277.641812)
		(end 277.456138 -277.641812)
		(width 0.101854)
		(layer "F.Cu")
		(net "M_C_CPU0_SA_CB<2>")
	)
	(segment
		(start 279.950672 -277.641812)
		(end 277.852886 -277.641812)
		(width 0.1016)
		(layer "F.Cu")
		(net "M_C_CPU0_SA_CB<2>")
	)
	(segment
		(start 344.653362 -261.522718)
		(end 344.653362 -262.058404)
		(width 0.20066)
		(layer "F.Cu")
		(net "M_C_CPU0_SA_CB<2>")
	)
	(segment
		(start 301.350934 -272.580862)
		(end 301.025814 -272.580862)
		(width 0.18288)
		(layer "In6.Cu")
		(net "M_C_CPU0_SA_CB<2>")
	)
	(segment
		(start 292.862508 -274.855686)
		(end 292.679628 -275.038566)
		(width 0.18288)
		(layer "In6.Cu")
		(net "M_C_CPU0_SA_CB<2>")
	)
	(segment
		(start 289.359086 -276.141434)
		(end 288.869628 -276.630892)
		(width 0.18288)
		(layer "In6.Cu")
		(net "M_C_CPU0_SA_CB<2>")
	)
	(segment
		(start 341.176864 -262.548116)
		(end 341.162132 -262.556752)
		(width 0.088646)
		(layer "In6.Cu")
		(net "M_C_CPU0_SA_CB<2>")
	)
	(segment
		(start 297.17492 -274.24126)
		(end 293.045388 -274.24126)
		(width 0.18288)
		(layer "In6.Cu")
		(net "M_C_CPU0_SA_CB<2>")
	)
	(segment
		(start 307.380894 -271.445736)
		(end 306.745894 -270.810736)
		(width 0.18288)
		(layer "In6.Cu")
		(net "M_C_CPU0_SA_CB<2>")
	)
	(segment
		(start 293.045388 -274.24126)
		(end 292.862508 -274.42414)
		(width 0.18288)
		(layer "In6.Cu")
		(net "M_C_CPU0_SA_CB<2>")
	)
	(segment
		(start 329.743562 -263.919208)
		(end 326.572118 -265.232642)
		(width 0.18288)
		(layer "In6.Cu")
		(net "M_C_CPU0_SA_CB<2>")
	)
	(segment
		(start 301.716694 -271.690846)
		(end 301.533814 -271.873726)
		(width 0.18288)
		(layer "In6.Cu")
		(net "M_C_CPU0_SA_CB<2>")
	)
	(segment
		(start 337.802474 -262.554212)
		(end 337.79206 -262.548116)
		(width 0.088646)
		(layer "In6.Cu")
		(net "M_C_CPU0_SA_CB<2>")
	)
	(segment
		(start 298.256452 -273.159728)
		(end 297.17492 -274.24126)
		(width 0.18288)
		(layer "In6.Cu")
		(net "M_C_CPU0_SA_CB<2>")
	)
	(segment
		(start 301.025814 -272.580862)
		(end 300.842934 -272.397982)
		(width 0.18288)
		(layer "In6.Cu")
		(net "M_C_CPU0_SA_CB<2>")
	)
	(segment
		(start 290.106354 -275.652738)
		(end 290.499546 -276.04593)
		(width 0.18288)
		(layer "In6.Cu")
		(net "M_C_CPU0_SA_CB<2>")
	)
	(segment
		(start 303.672494 -270.810736)
		(end 302.792384 -271.690846)
		(width 0.18288)
		(layer "In6.Cu")
		(net "M_C_CPU0_SA_CB<2>")
	)
	(segment
		(start 290.269422 -276.534626)
		(end 290.01085 -276.534626)
		(width 0.18288)
		(layer "In6.Cu")
		(net "M_C_CPU0_SA_CB<2>")
	)
	(segment
		(start 290.499546 -276.04593)
		(end 290.499546 -276.304502)
		(width 0.18288)
		(layer "In6.Cu")
		(net "M_C_CPU0_SA_CB<2>")
	)
	(segment
		(start 301.533814 -271.873726)
		(end 301.533814 -272.397982)
		(width 0.18288)
		(layer "In6.Cu")
		(net "M_C_CPU0_SA_CB<2>")
	)
	(segment
		(start 338.742528 -262.554212)
		(end 338.732114 -262.548116)
		(width 0.088646)
		(layer "In6.Cu")
		(net "M_C_CPU0_SA_CB<2>")
	)
	(segment
		(start 340.237064 -262.548116)
		(end 340.222332 -262.556752)
		(width 0.088646)
		(layer "In6.Cu")
		(net "M_C_CPU0_SA_CB<2>")
	)
	(segment
		(start 298.256452 -272.159222)
		(end 298.256452 -273.159728)
		(width 0.18288)
		(layer "In6.Cu")
		(net "M_C_CPU0_SA_CB<2>")
	)
	(segment
		(start 316.20333 -267.34135)
		(end 314.400692 -269.143988)
		(width 0.18288)
		(layer "In6.Cu")
		(net "M_C_CPU0_SA_CB<2>")
	)
	(segment
		(start 291.988748 -274.24126)
		(end 291.25926 -274.24126)
		(width 0.18288)
		(layer "In6.Cu")
		(net "M_C_CPU0_SA_CB<2>")
	)
	(segment
		(start 314.400692 -269.143988)
		(end 313.822842 -269.143988)
		(width 0.18288)
		(layer "In6.Cu")
		(net "M_C_CPU0_SA_CB<2>")
	)
	(segment
		(start 286.944308 -277.514812)
		(end 284.468824 -277.514812)
		(width 0.18288)
		(layer "In6.Cu")
		(net "M_C_CPU0_SA_CB<2>")
	)
	(segment
		(start 311.08396 -270.575786)
		(end 310.500776 -269.992602)
		(width 0.18288)
		(layer "In6.Cu")
		(net "M_C_CPU0_SA_CB<2>")
	)
	(segment
		(start 291.25926 -274.24126)
		(end 290.106354 -275.394166)
		(width 0.18288)
		(layer "In6.Cu")
		(net "M_C_CPU0_SA_CB<2>")
	)
	(segment
		(start 301.533814 -272.397982)
		(end 301.350934 -272.580862)
		(width 0.18288)
		(layer "In6.Cu")
		(net "M_C_CPU0_SA_CB<2>")
	)
	(segment
		(start 284.468824 -277.514812)
		(end 283.916882 -278.066754)
		(width 0.18288)
		(layer "In6.Cu")
		(net "M_C_CPU0_SA_CB<2>")
	)
	(segment
		(start 298.724828 -271.690846)
		(end 298.256452 -272.159222)
		(width 0.18288)
		(layer "In6.Cu")
		(net "M_C_CPU0_SA_CB<2>")
	)
	(segment
		(start 321.29603 -265.232642)
		(end 316.20333 -267.34135)
		(width 0.18288)
		(layer "In6.Cu")
		(net "M_C_CPU0_SA_CB<2>")
	)
	(segment
		(start 312.391044 -270.575786)
		(end 311.08396 -270.575786)
		(width 0.18288)
		(layer "In6.Cu")
		(net "M_C_CPU0_SA_CB<2>")
	)
	(segment
		(start 332.285594 -262.76173)
		(end 331.128116 -263.919208)
		(width 0.088646)
		(layer "In6.Cu")
		(net "M_C_CPU0_SA_CB<2>")
	)
	(segment
		(start 287.828228 -276.630892)
		(end 286.944308 -277.514812)
		(width 0.18288)
		(layer "In6.Cu")
		(net "M_C_CPU0_SA_CB<2>")
	)
	(segment
		(start 292.171628 -274.42414)
		(end 291.988748 -274.24126)
		(width 0.18288)
		(layer "In6.Cu")
		(net "M_C_CPU0_SA_CB<2>")
	)
	(segment
		(start 300.842934 -271.873726)
		(end 300.660054 -271.690846)
		(width 0.18288)
		(layer "In6.Cu")
		(net "M_C_CPU0_SA_CB<2>")
	)
	(segment
		(start 289.617658 -276.141434)
		(end 289.359086 -276.141434)
		(width 0.18288)
		(layer "In6.Cu")
		(net "M_C_CPU0_SA_CB<2>")
	)
	(segment
		(start 331.128116 -263.919208)
		(end 330.598272 -263.919208)
		(width 0.088646)
		(layer "In6.Cu")
		(net "M_C_CPU0_SA_CB<2>")
	)
	(segment
		(start 292.354508 -275.038566)
		(end 292.171628 -274.855686)
		(width 0.18288)
		(layer "In6.Cu")
		(net "M_C_CPU0_SA_CB<2>")
	)
	(segment
		(start 330.598272 -263.919208)
		(end 329.743562 -263.919208)
		(width 0.18288)
		(layer "In6.Cu")
		(net "M_C_CPU0_SA_CB<2>")
	)
	(segment
		(start 288.869628 -276.630892)
		(end 287.828228 -276.630892)
		(width 0.18288)
		(layer "In6.Cu")
		(net "M_C_CPU0_SA_CB<2>")
	)
	(segment
		(start 290.01085 -276.534626)
		(end 289.617658 -276.141434)
		(width 0.18288)
		(layer "In6.Cu")
		(net "M_C_CPU0_SA_CB<2>")
	)
	(segment
		(start 290.106354 -275.394166)
		(end 290.106354 -275.652738)
		(width 0.18288)
		(layer "In6.Cu")
		(net "M_C_CPU0_SA_CB<2>")
	)
	(segment
		(start 326.572118 -265.232642)
		(end 321.29603 -265.232642)
		(width 0.18288)
		(layer "In6.Cu")
		(net "M_C_CPU0_SA_CB<2>")
	)
	(segment
		(start 342.116664 -262.548116)
		(end 342.101932 -262.556752)
		(width 0.088646)
		(layer "In6.Cu")
		(net "M_C_CPU0_SA_CB<2>")
	)
	(segment
		(start 308.346094 -271.445736)
		(end 307.380894 -271.445736)
		(width 0.18288)
		(layer "In6.Cu")
		(net "M_C_CPU0_SA_CB<2>")
	)
	(segment
		(start 344.00236 -262.54456)
		(end 343.996264 -262.548116)
		(width 0.088646)
		(layer "In6.Cu")
		(net "M_C_CPU0_SA_CB<2>")
	)
	(segment
		(start 343.996264 -262.548116)
		(end 343.981532 -262.556752)
		(width 0.088646)
		(layer "In6.Cu")
		(net "M_C_CPU0_SA_CB<2>")
	)
	(segment
		(start 309.799228 -269.992602)
		(end 308.346094 -271.445736)
		(width 0.18288)
		(layer "In6.Cu")
		(net "M_C_CPU0_SA_CB<2>")
	)
	(segment
		(start 290.499546 -276.304502)
		(end 290.269422 -276.534626)
		(width 0.18288)
		(layer "In6.Cu")
		(net "M_C_CPU0_SA_CB<2>")
	)
	(segment
		(start 306.745894 -270.810736)
		(end 303.672494 -270.810736)
		(width 0.18288)
		(layer "In6.Cu")
		(net "M_C_CPU0_SA_CB<2>")
	)
	(segment
		(start 344.340942 -262.058658)
		(end 344.275156 -262.124444)
		(width 0.088646)
		(layer "In6.Cu")
		(net "M_C_CPU0_SA_CB<2>")
	)
	(segment
		(start 300.660054 -271.690846)
		(end 298.724828 -271.690846)
		(width 0.18288)
		(layer "In6.Cu")
		(net "M_C_CPU0_SA_CB<2>")
	)
	(segment
		(start 310.500776 -269.992602)
		(end 309.799228 -269.992602)
		(width 0.18288)
		(layer "In6.Cu")
		(net "M_C_CPU0_SA_CB<2>")
	)
	(segment
		(start 292.679628 -275.038566)
		(end 292.354508 -275.038566)
		(width 0.18288)
		(layer "In6.Cu")
		(net "M_C_CPU0_SA_CB<2>")
	)
	(segment
		(start 302.792384 -271.690846)
		(end 301.716694 -271.690846)
		(width 0.18288)
		(layer "In6.Cu")
		(net "M_C_CPU0_SA_CB<2>")
	)
	(segment
		(start 343.056464 -262.548116)
		(end 343.041732 -262.556752)
		(width 0.088646)
		(layer "In6.Cu")
		(net "M_C_CPU0_SA_CB<2>")
	)
	(segment
		(start 292.171628 -274.855686)
		(end 292.171628 -274.42414)
		(width 0.18288)
		(layer "In6.Cu")
		(net "M_C_CPU0_SA_CB<2>")
	)
	(segment
		(start 344.653616 -262.058658)
		(end 344.340942 -262.058658)
		(width 0.088646)
		(layer "In6.Cu")
		(net "M_C_CPU0_SA_CB<2>")
	)
	(segment
		(start 313.822842 -269.143988)
		(end 312.391044 -270.575786)
		(width 0.18288)
		(layer "In6.Cu")
		(net "M_C_CPU0_SA_CB<2>")
	)
	(segment
		(start 300.842934 -272.397982)
		(end 300.842934 -271.873726)
		(width 0.18288)
		(layer "In6.Cu")
		(net "M_C_CPU0_SA_CB<2>")
	)
	(segment
		(start 292.862508 -274.42414)
		(end 292.862508 -274.855686)
		(width 0.18288)
		(layer "In6.Cu")
		(net "M_C_CPU0_SA_CB<2>")
	)
	(arc
		(start 332.560676 -262.610346)
		(mid 332.412419 -262.666561)
		(end 332.285594 -262.76173)
		(width 0.088646)
		(layer "In6.Cu")
		(net "M_C_CPU0_SA_CB<2>")
	)
	(arc
		(start 339.297264 -262.548116)
		(mid 339.020705 -262.623859)
		(end 338.742528 -262.554212)
		(width 0.088646)
		(layer "In6.Cu")
		(net "M_C_CPU0_SA_CB<2>")
	)
	(arc
		(start 338.357718 -262.548116)
		(mid 338.080905 -262.623986)
		(end 337.802474 -262.554212)
		(width 0.088646)
		(layer "In6.Cu")
		(net "M_C_CPU0_SA_CB<2>")
	)
	(arc
		(start 340.222332 -262.556752)
		(mid 339.945857 -262.624072)
		(end 339.67166 -262.548116)
		(width 0.088646)
		(layer "In6.Cu")
		(net "M_C_CPU0_SA_CB<2>")
	)
	(arc
		(start 337.417664 -262.548116)
		(mid 337.134962 -262.623892)
		(end 336.85226 -262.548116)
		(width 0.088646)
		(layer "In6.Cu")
		(net "M_C_CPU0_SA_CB<2>")
	)
	(arc
		(start 343.43086 -262.548116)
		(mid 343.243662 -262.497973)
		(end 343.056464 -262.548116)
		(width 0.088646)
		(layer "In6.Cu")
		(net "M_C_CPU0_SA_CB<2>")
	)
	(arc
		(start 333.09306 -262.548116)
		(mid 332.905862 -262.497973)
		(end 332.718664 -262.548116)
		(width 0.088646)
		(layer "In6.Cu")
		(net "M_C_CPU0_SA_CB<2>")
	)
	(arc
		(start 336.85226 -262.548116)
		(mid 336.665062 -262.497973)
		(end 336.477864 -262.548116)
		(width 0.088646)
		(layer "In6.Cu")
		(net "M_C_CPU0_SA_CB<2>")
	)
	(arc
		(start 340.61146 -262.548116)
		(mid 340.424262 -262.497973)
		(end 340.237064 -262.548116)
		(width 0.088646)
		(layer "In6.Cu")
		(net "M_C_CPU0_SA_CB<2>")
	)
	(arc
		(start 341.55126 -262.548116)
		(mid 341.364062 -262.497973)
		(end 341.176864 -262.548116)
		(width 0.088646)
		(layer "In6.Cu")
		(net "M_C_CPU0_SA_CB<2>")
	)
	(arc
		(start 342.101932 -262.556752)
		(mid 341.825457 -262.624072)
		(end 341.55126 -262.548116)
		(width 0.088646)
		(layer "In6.Cu")
		(net "M_C_CPU0_SA_CB<2>")
	)
	(arc
		(start 339.67166 -262.548116)
		(mid 339.484462 -262.497973)
		(end 339.297264 -262.548116)
		(width 0.088646)
		(layer "In6.Cu")
		(net "M_C_CPU0_SA_CB<2>")
	)
	(arc
		(start 343.981532 -262.556752)
		(mid 343.705057 -262.624072)
		(end 343.43086 -262.548116)
		(width 0.088646)
		(layer "In6.Cu")
		(net "M_C_CPU0_SA_CB<2>")
	)
	(arc
		(start 343.041732 -262.556752)
		(mid 342.765257 -262.624072)
		(end 342.49106 -262.548116)
		(width 0.088646)
		(layer "In6.Cu")
		(net "M_C_CPU0_SA_CB<2>")
	)
	(arc
		(start 336.477864 -262.548116)
		(mid 336.195162 -262.623892)
		(end 335.91246 -262.548116)
		(width 0.088646)
		(layer "In6.Cu")
		(net "M_C_CPU0_SA_CB<2>")
	)
	(arc
		(start 342.49106 -262.548116)
		(mid 342.303862 -262.497973)
		(end 342.116664 -262.548116)
		(width 0.088646)
		(layer "In6.Cu")
		(net "M_C_CPU0_SA_CB<2>")
	)
	(arc
		(start 333.658464 -262.548116)
		(mid 333.375762 -262.623892)
		(end 333.09306 -262.548116)
		(width 0.088646)
		(layer "In6.Cu")
		(net "M_C_CPU0_SA_CB<2>")
	)
	(arc
		(start 335.91246 -262.548116)
		(mid 335.725262 -262.497973)
		(end 335.538064 -262.548116)
		(width 0.088646)
		(layer "In6.Cu")
		(net "M_C_CPU0_SA_CB<2>")
	)
	(arc
		(start 334.598264 -262.548116)
		(mid 334.315562 -262.623892)
		(end 334.03286 -262.548116)
		(width 0.088646)
		(layer "In6.Cu")
		(net "M_C_CPU0_SA_CB<2>")
	)
	(arc
		(start 334.03286 -262.548116)
		(mid 333.845662 -262.497973)
		(end 333.658464 -262.548116)
		(width 0.088646)
		(layer "In6.Cu")
		(net "M_C_CPU0_SA_CB<2>")
	)
	(arc
		(start 334.97266 -262.548116)
		(mid 334.785462 -262.497973)
		(end 334.598264 -262.548116)
		(width 0.088646)
		(layer "In6.Cu")
		(net "M_C_CPU0_SA_CB<2>")
	)
	(arc
		(start 332.718664 -262.548116)
		(mid 332.642015 -262.58518)
		(end 332.560676 -262.610346)
		(width 0.088646)
		(layer "In6.Cu")
		(net "M_C_CPU0_SA_CB<2>")
	)
	(arc
		(start 335.538064 -262.548116)
		(mid 335.255362 -262.623892)
		(end 334.97266 -262.548116)
		(width 0.088646)
		(layer "In6.Cu")
		(net "M_C_CPU0_SA_CB<2>")
	)
	(arc
		(start 344.275156 -262.124444)
		(mid 344.187868 -262.3664)
		(end 344.00236 -262.54456)
		(width 0.088646)
		(layer "In6.Cu")
		(net "M_C_CPU0_SA_CB<2>")
	)
	(arc
		(start 337.79206 -262.548116)
		(mid 337.604862 -262.497973)
		(end 337.417664 -262.548116)
		(width 0.088646)
		(layer "In6.Cu")
		(net "M_C_CPU0_SA_CB<2>")
	)
	(arc
		(start 338.732114 -262.548116)
		(mid 338.544916 -262.497973)
		(end 338.357718 -262.548116)
		(width 0.088646)
		(layer "In6.Cu")
		(net "M_C_CPU0_SA_CB<2>")
	)
	(arc
		(start 341.162132 -262.556752)
		(mid 340.885657 -262.624072)
		(end 340.61146 -262.548116)
		(width 0.088646)
		(layer "In6.Cu")
		(net "M_C_CPU0_SA_CB<2>")
	)
	(segment
		(start 343.243916 -261.244588)
		(end 343.243662 -261.244842)
		(width 0.20066)
		(layer "F.Cu")
		(net "M_C_CPU0_SA_CB<1>")
	)
	(segment
		(start 279.816814 -277.216616)
		(end 278.711914 -277.216616)
		(width 0.20066)
		(layer "F.Cu")
		(net "M_C_CPU0_SA_CB<1>")
	)
	(segment
		(start 276.138386 -276.791674)
		(end 274.152868 -276.791674)
		(width 0.1016)
		(layer "F.Cu")
		(net "M_C_CPU0_SA_CB<1>")
	)
	(segment
		(start 276.647656 -276.791674)
		(end 276.53488 -276.791674)
		(width 0.20066)
		(layer "F.Cu")
		(net "M_C_CPU0_SA_CB<1>")
	)
	(segment
		(start 273.37258 -276.954234)
		(end 273.37258 -277.273512)
		(width 0.20066)
		(layer "F.Cu")
		(net "M_C_CPU0_SA_CB<1>")
	)
	(segment
		(start 274.152868 -276.791674)
		(end 274.01012 -276.791674)
		(width 0.101854)
		(layer "F.Cu")
		(net "M_C_CPU0_SA_CB<1>")
	)
	(segment
		(start 278.711914 -277.216616)
		(end 277.072598 -277.216616)
		(width 0.20066)
		(layer "F.Cu")
		(net "M_C_CPU0_SA_CB<1>")
	)
	(segment
		(start 273.37258 -277.273512)
		(end 273.218148 -277.427944)
		(width 0.20066)
		(layer "F.Cu")
		(net "M_C_CPU0_SA_CB<1>")
	)
	(segment
		(start 273.218148 -277.427944)
		(end 272.713704 -277.427944)
		(width 0.20066)
		(layer "F.Cu")
		(net "M_C_CPU0_SA_CB<1>")
	)
	(segment
		(start 277.072598 -277.216616)
		(end 276.647656 -276.791674)
		(width 0.20066)
		(layer "F.Cu")
		(net "M_C_CPU0_SA_CB<1>")
	)
	(segment
		(start 272.502376 -277.216616)
		(end 271.168114 -277.216616)
		(width 0.20066)
		(layer "F.Cu")
		(net "M_C_CPU0_SA_CB<1>")
	)
	(segment
		(start 273.53514 -276.791674)
		(end 273.37258 -276.954234)
		(width 0.20066)
		(layer "F.Cu")
		(net "M_C_CPU0_SA_CB<1>")
	)
	(segment
		(start 276.53488 -276.791674)
		(end 276.138386 -276.791674)
		(width 0.101854)
		(layer "F.Cu")
		(net "M_C_CPU0_SA_CB<1>")
	)
	(segment
		(start 272.713704 -277.427944)
		(end 272.502376 -277.216616)
		(width 0.20066)
		(layer "F.Cu")
		(net "M_C_CPU0_SA_CB<1>")
	)
	(segment
		(start 274.01012 -276.791674)
		(end 273.53514 -276.791674)
		(width 0.20066)
		(layer "F.Cu")
		(net "M_C_CPU0_SA_CB<1>")
	)
	(segment
		(start 343.243916 -260.708902)
		(end 343.243916 -261.244588)
		(width 0.20066)
		(layer "F.Cu")
		(net "M_C_CPU0_SA_CB<1>")
	)
	(segment
		(start 320.618612 -263.703308)
		(end 315.139324 -265.972798)
		(width 0.18288)
		(layer "In6.Cu")
		(net "M_C_CPU0_SA_CB<1>")
	)
	(segment
		(start 285.761176 -275.091144)
		(end 283.436822 -275.091144)
		(width 0.18288)
		(layer "In6.Cu")
		(net "M_C_CPU0_SA_CB<1>")
	)
	(segment
		(start 312.087006 -268.348714)
		(end 311.404254 -268.348714)
		(width 0.18288)
		(layer "In6.Cu")
		(net "M_C_CPU0_SA_CB<1>")
	)
	(segment
		(start 292.013894 -271.861026)
		(end 291.048694 -271.861026)
		(width 0.18288)
		(layer "In6.Cu")
		(net "M_C_CPU0_SA_CB<1>")
	)
	(segment
		(start 286.476694 -274.375626)
		(end 285.761176 -275.091144)
		(width 0.18288)
		(layer "In6.Cu")
		(net "M_C_CPU0_SA_CB<1>")
	)
	(segment
		(start 283.011118 -276.036786)
		(end 282.269692 -276.036786)
		(width 0.18288)
		(layer "In6.Cu")
		(net "M_C_CPU0_SA_CB<1>")
	)
	(segment
		(start 314.23356 -266.878562)
		(end 313.557158 -266.878562)
		(width 0.18288)
		(layer "In6.Cu")
		(net "M_C_CPU0_SA_CB<1>")
	)
	(segment
		(start 295.671494 -271.6911)
		(end 293.224966 -271.6911)
		(width 0.18288)
		(layer "In6.Cu")
		(net "M_C_CPU0_SA_CB<1>")
	)
	(segment
		(start 331.738986 -261.619746)
		(end 330.961238 -262.397494)
		(width 0.088646)
		(layer "In6.Cu")
		(net "M_C_CPU0_SA_CB<1>")
	)
	(segment
		(start 281.426412 -276.386036)
		(end 281.187652 -276.286976)
		(width 0.18288)
		(layer "In6.Cu")
		(net "M_C_CPU0_SA_CB<1>")
	)
	(segment
		(start 298.222162 -269.140432)
		(end 295.671494 -271.6911)
		(width 0.18288)
		(layer "In6.Cu")
		(net "M_C_CPU0_SA_CB<1>")
	)
	(segment
		(start 342.116664 -261.5692)
		(end 342.101932 -261.560564)
		(width 0.088646)
		(layer "In6.Cu")
		(net "M_C_CPU0_SA_CB<1>")
	)
	(segment
		(start 280.450036 -276.79015)
		(end 280.096722 -276.936708)
		(width 0.18288)
		(layer "In6.Cu")
		(net "M_C_CPU0_SA_CB<1>")
	)
	(segment
		(start 280.795476 -275.818092)
		(end 280.49474 -275.942806)
		(width 0.18288)
		(layer "In6.Cu")
		(net "M_C_CPU0_SA_CB<1>")
	)
	(segment
		(start 281.187652 -276.286976)
		(end 281.034236 -275.917152)
		(width 0.18288)
		(layer "In6.Cu")
		(net "M_C_CPU0_SA_CB<1>")
	)
	(segment
		(start 310.756554 -267.701014)
		(end 309.628794 -267.701014)
		(width 0.18288)
		(layer "In6.Cu")
		(net "M_C_CPU0_SA_CB<1>")
	)
	(segment
		(start 330.961238 -262.397494)
		(end 330.598272 -262.397494)
		(width 0.088646)
		(layer "In6.Cu")
		(net "M_C_CPU0_SA_CB<1>")
	)
	(segment
		(start 315.139324 -265.972798)
		(end 314.23356 -266.878562)
		(width 0.18288)
		(layer "In6.Cu")
		(net "M_C_CPU0_SA_CB<1>")
	)
	(segment
		(start 287.467294 -274.375626)
		(end 286.476694 -274.375626)
		(width 0.18288)
		(layer "In6.Cu")
		(net "M_C_CPU0_SA_CB<1>")
	)
	(segment
		(start 309.628794 -267.701014)
		(end 309.040022 -268.289786)
		(width 0.18288)
		(layer "In6.Cu")
		(net "M_C_CPU0_SA_CB<1>")
	)
	(segment
		(start 331.966062 -261.619746)
		(end 331.738986 -261.619746)
		(width 0.088646)
		(layer "In6.Cu")
		(net "M_C_CPU0_SA_CB<1>")
	)
	(segment
		(start 337.428586 -261.575296)
		(end 337.417664 -261.568946)
		(width 0.088646)
		(layer "In6.Cu")
		(net "M_C_CPU0_SA_CB<1>")
	)
	(segment
		(start 326.360028 -263.703308)
		(end 320.618612 -263.703308)
		(width 0.18288)
		(layer "In6.Cu")
		(net "M_C_CPU0_SA_CB<1>")
	)
	(segment
		(start 302.99914 -269.140432)
		(end 298.222162 -269.140432)
		(width 0.18288)
		(layer "In6.Cu")
		(net "M_C_CPU0_SA_CB<1>")
	)
	(segment
		(start 280.49474 -275.942806)
		(end 280.39568 -276.181566)
		(width 0.18288)
		(layer "In6.Cu")
		(net "M_C_CPU0_SA_CB<1>")
	)
	(segment
		(start 303.849786 -268.289786)
		(end 302.99914 -269.140432)
		(width 0.18288)
		(layer "In6.Cu")
		(net "M_C_CPU0_SA_CB<1>")
	)
	(segment
		(start 309.040022 -268.289786)
		(end 303.849786 -268.289786)
		(width 0.18288)
		(layer "In6.Cu")
		(net "M_C_CPU0_SA_CB<1>")
	)
	(segment
		(start 293.013892 -271.480026)
		(end 292.394894 -271.480026)
		(width 0.18288)
		(layer "In6.Cu")
		(net "M_C_CPU0_SA_CB<1>")
	)
	(segment
		(start 283.436822 -275.091144)
		(end 283.138118 -275.389848)
		(width 0.18288)
		(layer "In6.Cu")
		(net "M_C_CPU0_SA_CB<1>")
	)
	(segment
		(start 293.224966 -271.6911)
		(end 293.013892 -271.480026)
		(width 0.18288)
		(layer "In6.Cu")
		(net "M_C_CPU0_SA_CB<1>")
	)
	(segment
		(start 341.176864 -261.5692)
		(end 341.162132 -261.560564)
		(width 0.088646)
		(layer "In6.Cu")
		(net "M_C_CPU0_SA_CB<1>")
	)
	(segment
		(start 292.394894 -271.480026)
		(end 292.013894 -271.861026)
		(width 0.18288)
		(layer "In6.Cu")
		(net "M_C_CPU0_SA_CB<1>")
	)
	(segment
		(start 340.237064 -261.5692)
		(end 340.222332 -261.560564)
		(width 0.088646)
		(layer "In6.Cu")
		(net "M_C_CPU0_SA_CB<1>")
	)
	(segment
		(start 280.39568 -276.181566)
		(end 280.549096 -276.55139)
		(width 0.18288)
		(layer "In6.Cu")
		(net "M_C_CPU0_SA_CB<1>")
	)
	(segment
		(start 311.404254 -268.348714)
		(end 310.756554 -267.701014)
		(width 0.18288)
		(layer "In6.Cu")
		(net "M_C_CPU0_SA_CB<1>")
	)
	(segment
		(start 337.417664 -261.568946)
		(end 337.402932 -261.56031)
		(width 0.088646)
		(layer "In6.Cu")
		(net "M_C_CPU0_SA_CB<1>")
	)
	(segment
		(start 288.285174 -273.557746)
		(end 287.467294 -274.375626)
		(width 0.18288)
		(layer "In6.Cu")
		(net "M_C_CPU0_SA_CB<1>")
	)
	(segment
		(start 336.85226 -261.568946)
		(end 336.841338 -261.575296)
		(width 0.088646)
		(layer "In6.Cu")
		(net "M_C_CPU0_SA_CB<1>")
	)
	(segment
		(start 289.351974 -273.557746)
		(end 288.285174 -273.557746)
		(width 0.18288)
		(layer "In6.Cu")
		(net "M_C_CPU0_SA_CB<1>")
	)
	(segment
		(start 313.557158 -266.878562)
		(end 312.087006 -268.348714)
		(width 0.18288)
		(layer "In6.Cu")
		(net "M_C_CPU0_SA_CB<1>")
	)
	(segment
		(start 282.269692 -276.036786)
		(end 281.426412 -276.386036)
		(width 0.18288)
		(layer "In6.Cu")
		(net "M_C_CPU0_SA_CB<1>")
	)
	(segment
		(start 281.034236 -275.917152)
		(end 280.795476 -275.818092)
		(width 0.18288)
		(layer "In6.Cu")
		(net "M_C_CPU0_SA_CB<1>")
	)
	(segment
		(start 291.048694 -271.861026)
		(end 289.351974 -273.557746)
		(width 0.18288)
		(layer "In6.Cu")
		(net "M_C_CPU0_SA_CB<1>")
	)
	(segment
		(start 330.598272 -262.397494)
		(end 329.51293 -262.397494)
		(width 0.18288)
		(layer "In6.Cu")
		(net "M_C_CPU0_SA_CB<1>")
	)
	(segment
		(start 283.138118 -275.389848)
		(end 283.138118 -275.909786)
		(width 0.18288)
		(layer "In6.Cu")
		(net "M_C_CPU0_SA_CB<1>")
	)
	(segment
		(start 329.51293 -262.397494)
		(end 326.360028 -263.703308)
		(width 0.18288)
		(layer "In6.Cu")
		(net "M_C_CPU0_SA_CB<1>")
	)
	(segment
		(start 283.138118 -275.909786)
		(end 283.011118 -276.036786)
		(width 0.18288)
		(layer "In6.Cu")
		(net "M_C_CPU0_SA_CB<1>")
	)
	(segment
		(start 280.096722 -276.936708)
		(end 279.816814 -277.216616)
		(width 0.18288)
		(layer "In6.Cu")
		(net "M_C_CPU0_SA_CB<1>")
	)
	(segment
		(start 280.549096 -276.55139)
		(end 280.450036 -276.79015)
		(width 0.18288)
		(layer "In6.Cu")
		(net "M_C_CPU0_SA_CB<1>")
	)
	(arc
		(start 342.49106 -261.5692)
		(mid 342.303862 -261.619343)
		(end 342.116664 -261.5692)
		(width 0.088646)
		(layer "In6.Cu")
		(net "M_C_CPU0_SA_CB<1>")
	)
	(arc
		(start 339.67166 -261.5692)
		(mid 339.484462 -261.619343)
		(end 339.297264 -261.5692)
		(width 0.088646)
		(layer "In6.Cu")
		(net "M_C_CPU0_SA_CB<1>")
	)
	(arc
		(start 338.357464 -261.5692)
		(mid 338.074762 -261.493424)
		(end 337.79206 -261.5692)
		(width 0.088646)
		(layer "In6.Cu")
		(net "M_C_CPU0_SA_CB<1>")
	)
	(arc
		(start 337.402932 -261.56031)
		(mid 337.126457 -261.49299)
		(end 336.85226 -261.568946)
		(width 0.088646)
		(layer "In6.Cu")
		(net "M_C_CPU0_SA_CB<1>")
	)
	(arc
		(start 338.73186 -261.5692)
		(mid 338.544662 -261.619343)
		(end 338.357464 -261.5692)
		(width 0.088646)
		(layer "In6.Cu")
		(net "M_C_CPU0_SA_CB<1>")
	)
	(arc
		(start 341.162132 -261.560564)
		(mid 340.885657 -261.493244)
		(end 340.61146 -261.5692)
		(width 0.088646)
		(layer "In6.Cu")
		(net "M_C_CPU0_SA_CB<1>")
	)
	(arc
		(start 334.598264 -261.5692)
		(mid 334.315562 -261.493424)
		(end 334.03286 -261.5692)
		(width 0.088646)
		(layer "In6.Cu")
		(net "M_C_CPU0_SA_CB<1>")
	)
	(arc
		(start 335.91246 -261.5692)
		(mid 335.725262 -261.619343)
		(end 335.538064 -261.5692)
		(width 0.088646)
		(layer "In6.Cu")
		(net "M_C_CPU0_SA_CB<1>")
	)
	(arc
		(start 334.03286 -261.5692)
		(mid 333.845662 -261.619343)
		(end 333.658464 -261.5692)
		(width 0.088646)
		(layer "In6.Cu")
		(net "M_C_CPU0_SA_CB<1>")
	)
	(arc
		(start 332.15326 -261.5692)
		(mid 332.062988 -261.606799)
		(end 331.966062 -261.619746)
		(width 0.088646)
		(layer "In6.Cu")
		(net "M_C_CPU0_SA_CB<1>")
	)
	(arc
		(start 337.79206 -261.5692)
		(mid 337.611116 -261.619291)
		(end 337.428586 -261.575296)
		(width 0.088646)
		(layer "In6.Cu")
		(net "M_C_CPU0_SA_CB<1>")
	)
	(arc
		(start 340.61146 -261.5692)
		(mid 340.424262 -261.619343)
		(end 340.237064 -261.5692)
		(width 0.088646)
		(layer "In6.Cu")
		(net "M_C_CPU0_SA_CB<1>")
	)
	(arc
		(start 341.55126 -261.5692)
		(mid 341.364062 -261.619343)
		(end 341.176864 -261.5692)
		(width 0.088646)
		(layer "In6.Cu")
		(net "M_C_CPU0_SA_CB<1>")
	)
	(arc
		(start 342.101932 -261.560564)
		(mid 341.825457 -261.493244)
		(end 341.55126 -261.5692)
		(width 0.088646)
		(layer "In6.Cu")
		(net "M_C_CPU0_SA_CB<1>")
	)
	(arc
		(start 332.718664 -261.5692)
		(mid 332.435962 -261.493424)
		(end 332.15326 -261.5692)
		(width 0.088646)
		(layer "In6.Cu")
		(net "M_C_CPU0_SA_CB<1>")
	)
	(arc
		(start 333.658464 -261.5692)
		(mid 333.375762 -261.493424)
		(end 333.09306 -261.5692)
		(width 0.088646)
		(layer "In6.Cu")
		(net "M_C_CPU0_SA_CB<1>")
	)
	(arc
		(start 339.297264 -261.5692)
		(mid 339.014562 -261.493424)
		(end 338.73186 -261.5692)
		(width 0.088646)
		(layer "In6.Cu")
		(net "M_C_CPU0_SA_CB<1>")
	)
	(arc
		(start 336.477864 -261.5692)
		(mid 336.195162 -261.493424)
		(end 335.91246 -261.5692)
		(width 0.088646)
		(layer "In6.Cu")
		(net "M_C_CPU0_SA_CB<1>")
	)
	(arc
		(start 333.09306 -261.5692)
		(mid 332.905862 -261.619343)
		(end 332.718664 -261.5692)
		(width 0.088646)
		(layer "In6.Cu")
		(net "M_C_CPU0_SA_CB<1>")
	)
	(arc
		(start 334.97266 -261.5692)
		(mid 334.785462 -261.619343)
		(end 334.598264 -261.5692)
		(width 0.088646)
		(layer "In6.Cu")
		(net "M_C_CPU0_SA_CB<1>")
	)
	(arc
		(start 340.222332 -261.560564)
		(mid 339.945857 -261.493244)
		(end 339.67166 -261.5692)
		(width 0.088646)
		(layer "In6.Cu")
		(net "M_C_CPU0_SA_CB<1>")
	)
	(arc
		(start 336.841338 -261.575296)
		(mid 336.658808 -261.61932)
		(end 336.477864 -261.5692)
		(width 0.088646)
		(layer "In6.Cu")
		(net "M_C_CPU0_SA_CB<1>")
	)
	(arc
		(start 335.538064 -261.5692)
		(mid 335.255362 -261.493424)
		(end 334.97266 -261.5692)
		(width 0.088646)
		(layer "In6.Cu")
		(net "M_C_CPU0_SA_CB<1>")
	)
	(arc
		(start 343.243662 -261.244842)
		(mid 342.857902 -261.385073)
		(end 342.49106 -261.5692)
		(width 0.088646)
		(layer "In6.Cu")
		(net "M_C_CPU0_SA_CB<1>")
	)
	(segment
		(start 272.502376 -278.916638)
		(end 271.168114 -278.916638)
		(width 0.20066)
		(layer "F.Cu")
		(net "M_C_CPU0_SA_CB<0>")
	)
	(segment
		(start 273.37258 -278.693118)
		(end 273.37258 -278.982678)
		(width 0.20066)
		(layer "F.Cu")
		(net "M_C_CPU0_SA_CB<0>")
	)
	(segment
		(start 272.741136 -279.155398)
		(end 272.502376 -278.916638)
		(width 0.20066)
		(layer "F.Cu")
		(net "M_C_CPU0_SA_CB<0>")
	)
	(segment
		(start 343.713562 -261.522718)
		(end 343.713562 -262.058404)
		(width 0.20066)
		(layer "F.Cu")
		(net "M_C_CPU0_SA_CB<0>")
	)
	(segment
		(start 343.713562 -262.058404)
		(end 343.713816 -262.058658)
		(width 0.20066)
		(layer "F.Cu")
		(net "M_C_CPU0_SA_CB<0>")
	)
	(segment
		(start 276.469094 -278.491696)
		(end 274.40001 -278.491696)
		(width 0.1016)
		(layer "F.Cu")
		(net "M_C_CPU0_SA_CB<0>")
	)
	(segment
		(start 277.342854 -278.916638)
		(end 276.917912 -278.491696)
		(width 0.20066)
		(layer "F.Cu")
		(net "M_C_CPU0_SA_CB<0>")
	)
	(segment
		(start 278.711914 -278.916638)
		(end 277.342854 -278.916638)
		(width 0.20066)
		(layer "F.Cu")
		(net "M_C_CPU0_SA_CB<0>")
	)
	(segment
		(start 276.917912 -278.491696)
		(end 276.534626 -278.491696)
		(width 0.20066)
		(layer "F.Cu")
		(net "M_C_CPU0_SA_CB<0>")
	)
	(segment
		(start 279.816814 -278.916638)
		(end 278.711914 -278.916638)
		(width 0.20066)
		(layer "F.Cu")
		(net "M_C_CPU0_SA_CB<0>")
	)
	(segment
		(start 276.534626 -278.491696)
		(end 276.469094 -278.491696)
		(width 0.101854)
		(layer "F.Cu")
		(net "M_C_CPU0_SA_CB<0>")
	)
	(segment
		(start 273.574002 -278.491696)
		(end 273.37258 -278.693118)
		(width 0.20066)
		(layer "F.Cu")
		(net "M_C_CPU0_SA_CB<0>")
	)
	(segment
		(start 274.009866 -278.491696)
		(end 273.574002 -278.491696)
		(width 0.20066)
		(layer "F.Cu")
		(net "M_C_CPU0_SA_CB<0>")
	)
	(segment
		(start 274.40001 -278.491696)
		(end 274.009866 -278.491696)
		(width 0.101854)
		(layer "F.Cu")
		(net "M_C_CPU0_SA_CB<0>")
	)
	(segment
		(start 273.19986 -279.155398)
		(end 272.741136 -279.155398)
		(width 0.20066)
		(layer "F.Cu")
		(net "M_C_CPU0_SA_CB<0>")
	)
	(segment
		(start 273.37258 -278.982678)
		(end 273.19986 -279.155398)
		(width 0.20066)
		(layer "F.Cu")
		(net "M_C_CPU0_SA_CB<0>")
	)
	(segment
		(start 321.138042 -264.72007)
		(end 315.557662 -267.030962)
		(width 0.18288)
		(layer "In6.Cu")
		(net "M_C_CPU0_SA_CB<0>")
	)
	(segment
		(start 342.036146 -262.37438)
		(end 342.021414 -262.383016)
		(width 0.088646)
		(layer "In6.Cu")
		(net "M_C_CPU0_SA_CB<0>")
	)
	(segment
		(start 291.149024 -273.391376)
		(end 289.715448 -274.824952)
		(width 0.18288)
		(layer "In6.Cu")
		(net "M_C_CPU0_SA_CB<0>")
	)
	(segment
		(start 344.02649 -262.058658)
		(end 344.083894 -262.116062)
		(width 0.088646)
		(layer "In6.Cu")
		(net "M_C_CPU0_SA_CB<0>")
	)
	(segment
		(start 297.666918 -271.842738)
		(end 297.666918 -272.83537)
		(width 0.18288)
		(layer "In6.Cu")
		(net "M_C_CPU0_SA_CB<0>")
	)
	(segment
		(start 315.557662 -267.030962)
		(end 314.29579 -268.292834)
		(width 0.18288)
		(layer "In6.Cu")
		(net "M_C_CPU0_SA_CB<0>")
	)
	(segment
		(start 289.715448 -274.824952)
		(end 288.75482 -274.824952)
		(width 0.18288)
		(layer "In6.Cu")
		(net "M_C_CPU0_SA_CB<0>")
	)
	(segment
		(start 338.827364 -262.383016)
		(end 338.812632 -262.37438)
		(width 0.088646)
		(layer "In6.Cu")
		(net "M_C_CPU0_SA_CB<0>")
	)
	(segment
		(start 326.50811 -264.72007)
		(end 321.138042 -264.72007)
		(width 0.18288)
		(layer "In6.Cu")
		(net "M_C_CPU0_SA_CB<0>")
	)
	(segment
		(start 302.918876 -270.840962)
		(end 298.668694 -270.840962)
		(width 0.18288)
		(layer "In6.Cu")
		(net "M_C_CPU0_SA_CB<0>")
	)
	(segment
		(start 298.668694 -270.840962)
		(end 297.666918 -271.842738)
		(width 0.18288)
		(layer "In6.Cu")
		(net "M_C_CPU0_SA_CB<0>")
	)
	(segment
		(start 336.947764 -262.383016)
		(end 336.948018 -262.383016)
		(width 0.088646)
		(layer "In6.Cu")
		(net "M_C_CPU0_SA_CB<0>")
	)
	(segment
		(start 307.979064 -270.874236)
		(end 307.571394 -270.874236)
		(width 0.18288)
		(layer "In6.Cu")
		(net "M_C_CPU0_SA_CB<0>")
	)
	(segment
		(start 342.975946 -262.37438)
		(end 342.961214 -262.383016)
		(width 0.088646)
		(layer "In6.Cu")
		(net "M_C_CPU0_SA_CB<0>")
	)
	(segment
		(start 312.11139 -270.048736)
		(end 311.499758 -270.048736)
		(width 0.18288)
		(layer "In6.Cu")
		(net "M_C_CPU0_SA_CB<0>")
	)
	(segment
		(start 341.096346 -262.37438)
		(end 341.081614 -262.383016)
		(width 0.088646)
		(layer "In6.Cu")
		(net "M_C_CPU0_SA_CB<0>")
	)
	(segment
		(start 288.75482 -274.824952)
		(end 287.808416 -275.771356)
		(width 0.18288)
		(layer "In6.Cu")
		(net "M_C_CPU0_SA_CB<0>")
	)
	(segment
		(start 336.392774 -262.37692)
		(end 336.38236 -262.383016)
		(width 0.088646)
		(layer "In6.Cu")
		(net "M_C_CPU0_SA_CB<0>")
	)
	(segment
		(start 343.909904 -262.377936)
		(end 343.901014 -262.383016)
		(width 0.088646)
		(layer "In6.Cu")
		(net "M_C_CPU0_SA_CB<0>")
	)
	(segment
		(start 330.598272 -263.406636)
		(end 329.679046 -263.406636)
		(width 0.18288)
		(layer "In6.Cu")
		(net "M_C_CPU0_SA_CB<0>")
	)
	(segment
		(start 343.713816 -262.058658)
		(end 344.02649 -262.058658)
		(width 0.088646)
		(layer "In6.Cu")
		(net "M_C_CPU0_SA_CB<0>")
	)
	(segment
		(start 314.29579 -268.292834)
		(end 313.867292 -268.292834)
		(width 0.18288)
		(layer "In6.Cu")
		(net "M_C_CPU0_SA_CB<0>")
	)
	(segment
		(start 332.207362 -262.54202)
		(end 331.342746 -263.406636)
		(width 0.088646)
		(layer "In6.Cu")
		(net "M_C_CPU0_SA_CB<0>")
	)
	(segment
		(start 329.679046 -263.406636)
		(end 326.50811 -264.72007)
		(width 0.18288)
		(layer "In6.Cu")
		(net "M_C_CPU0_SA_CB<0>")
	)
	(segment
		(start 310.595264 -269.144242)
		(end 309.709058 -269.144242)
		(width 0.18288)
		(layer "In6.Cu")
		(net "M_C_CPU0_SA_CB<0>")
	)
	(segment
		(start 306.999894 -270.302736)
		(end 303.457102 -270.302736)
		(width 0.18288)
		(layer "In6.Cu")
		(net "M_C_CPU0_SA_CB<0>")
	)
	(segment
		(start 340.156546 -262.37438)
		(end 340.141814 -262.383016)
		(width 0.088646)
		(layer "In6.Cu")
		(net "M_C_CPU0_SA_CB<0>")
	)
	(segment
		(start 313.867292 -268.292834)
		(end 312.11139 -270.048736)
		(width 0.18288)
		(layer "In6.Cu")
		(net "M_C_CPU0_SA_CB<0>")
	)
	(segment
		(start 307.571394 -270.874236)
		(end 306.999894 -270.302736)
		(width 0.18288)
		(layer "In6.Cu")
		(net "M_C_CPU0_SA_CB<0>")
	)
	(segment
		(start 287.808416 -275.771356)
		(end 286.84601 -275.771356)
		(width 0.18288)
		(layer "In6.Cu")
		(net "M_C_CPU0_SA_CB<0>")
	)
	(segment
		(start 282.866846 -276.788372)
		(end 280.73858 -278.916638)
		(width 0.18288)
		(layer "In6.Cu")
		(net "M_C_CPU0_SA_CB<0>")
	)
	(segment
		(start 331.342746 -263.406636)
		(end 330.598272 -263.406636)
		(width 0.088646)
		(layer "In6.Cu")
		(net "M_C_CPU0_SA_CB<0>")
	)
	(segment
		(start 297.666918 -272.83537)
		(end 297.110912 -273.391376)
		(width 0.18288)
		(layer "In6.Cu")
		(net "M_C_CPU0_SA_CB<0>")
	)
	(segment
		(start 303.457102 -270.302736)
		(end 302.918876 -270.840962)
		(width 0.18288)
		(layer "In6.Cu")
		(net "M_C_CPU0_SA_CB<0>")
	)
	(segment
		(start 285.828994 -276.788372)
		(end 282.866846 -276.788372)
		(width 0.18288)
		(layer "In6.Cu")
		(net "M_C_CPU0_SA_CB<0>")
	)
	(segment
		(start 286.84601 -275.771356)
		(end 285.828994 -276.788372)
		(width 0.18288)
		(layer "In6.Cu")
		(net "M_C_CPU0_SA_CB<0>")
	)
	(segment
		(start 311.499758 -270.048736)
		(end 310.595264 -269.144242)
		(width 0.18288)
		(layer "In6.Cu")
		(net "M_C_CPU0_SA_CB<0>")
	)
	(segment
		(start 280.73858 -278.916638)
		(end 279.816814 -278.916638)
		(width 0.18288)
		(layer "In6.Cu")
		(net "M_C_CPU0_SA_CB<0>")
	)
	(segment
		(start 297.110912 -273.391376)
		(end 291.149024 -273.391376)
		(width 0.18288)
		(layer "In6.Cu")
		(net "M_C_CPU0_SA_CB<0>")
	)
	(segment
		(start 339.212174 -262.37692)
		(end 339.20176 -262.383016)
		(width 0.088646)
		(layer "In6.Cu")
		(net "M_C_CPU0_SA_CB<0>")
	)
	(segment
		(start 309.709058 -269.144242)
		(end 307.979064 -270.874236)
		(width 0.18288)
		(layer "In6.Cu")
		(net "M_C_CPU0_SA_CB<0>")
	)
	(arc
		(start 342.586818 -262.383016)
		(mid 342.312619 -262.307181)
		(end 342.036146 -262.37438)
		(width 0.088646)
		(layer "In6.Cu")
		(net "M_C_CPU0_SA_CB<0>")
	)
	(arc
		(start 340.141814 -262.383016)
		(mid 339.954616 -262.433159)
		(end 339.767418 -262.383016)
		(width 0.088646)
		(layer "In6.Cu")
		(net "M_C_CPU0_SA_CB<0>")
	)
	(arc
		(start 335.068164 -262.383016)
		(mid 334.785462 -262.30724)
		(end 334.50276 -262.383016)
		(width 0.088646)
		(layer "In6.Cu")
		(net "M_C_CPU0_SA_CB<0>")
	)
	(arc
		(start 336.38236 -262.383016)
		(mid 336.195162 -262.433159)
		(end 336.007964 -262.383016)
		(width 0.088646)
		(layer "In6.Cu")
		(net "M_C_CPU0_SA_CB<0>")
	)
	(arc
		(start 336.948018 -262.383016)
		(mid 336.671205 -262.307146)
		(end 336.392774 -262.37692)
		(width 0.088646)
		(layer "In6.Cu")
		(net "M_C_CPU0_SA_CB<0>")
	)
	(arc
		(start 337.887564 -262.383016)
		(mid 337.604862 -262.30724)
		(end 337.32216 -262.383016)
		(width 0.088646)
		(layer "In6.Cu")
		(net "M_C_CPU0_SA_CB<0>")
	)
	(arc
		(start 332.62316 -262.383016)
		(mid 332.541674 -262.417987)
		(end 332.45425 -262.4328)
		(width 0.088646)
		(layer "In6.Cu")
		(net "M_C_CPU0_SA_CB<0>")
	)
	(arc
		(start 334.50276 -262.383016)
		(mid 334.315562 -262.433159)
		(end 334.128364 -262.383016)
		(width 0.088646)
		(layer "In6.Cu")
		(net "M_C_CPU0_SA_CB<0>")
	)
	(arc
		(start 333.56296 -262.383016)
		(mid 333.375762 -262.433159)
		(end 333.188564 -262.383016)
		(width 0.088646)
		(layer "In6.Cu")
		(net "M_C_CPU0_SA_CB<0>")
	)
	(arc
		(start 341.081614 -262.383016)
		(mid 340.894416 -262.433159)
		(end 340.707218 -262.383016)
		(width 0.088646)
		(layer "In6.Cu")
		(net "M_C_CPU0_SA_CB<0>")
	)
	(arc
		(start 339.767418 -262.383016)
		(mid 339.490605 -262.307146)
		(end 339.212174 -262.37692)
		(width 0.088646)
		(layer "In6.Cu")
		(net "M_C_CPU0_SA_CB<0>")
	)
	(arc
		(start 340.707218 -262.383016)
		(mid 340.433019 -262.307181)
		(end 340.156546 -262.37438)
		(width 0.088646)
		(layer "In6.Cu")
		(net "M_C_CPU0_SA_CB<0>")
	)
	(arc
		(start 334.128364 -262.383016)
		(mid 333.845662 -262.30724)
		(end 333.56296 -262.383016)
		(width 0.088646)
		(layer "In6.Cu")
		(net "M_C_CPU0_SA_CB<0>")
	)
	(arc
		(start 343.901014 -262.383016)
		(mid 343.713816 -262.433159)
		(end 343.526618 -262.383016)
		(width 0.088646)
		(layer "In6.Cu")
		(net "M_C_CPU0_SA_CB<0>")
	)
	(arc
		(start 339.20176 -262.383016)
		(mid 339.014562 -262.433159)
		(end 338.827364 -262.383016)
		(width 0.088646)
		(layer "In6.Cu")
		(net "M_C_CPU0_SA_CB<0>")
	)
	(arc
		(start 338.812632 -262.37438)
		(mid 338.536157 -262.30706)
		(end 338.26196 -262.383016)
		(width 0.088646)
		(layer "In6.Cu")
		(net "M_C_CPU0_SA_CB<0>")
	)
	(arc
		(start 338.26196 -262.383016)
		(mid 338.074762 -262.433159)
		(end 337.887564 -262.383016)
		(width 0.088646)
		(layer "In6.Cu")
		(net "M_C_CPU0_SA_CB<0>")
	)
	(arc
		(start 342.021414 -262.383016)
		(mid 341.834216 -262.433159)
		(end 341.647018 -262.383016)
		(width 0.088646)
		(layer "In6.Cu")
		(net "M_C_CPU0_SA_CB<0>")
	)
	(arc
		(start 332.45425 -262.4328)
		(mid 332.320597 -262.464354)
		(end 332.207362 -262.54202)
		(width 0.088646)
		(layer "In6.Cu")
		(net "M_C_CPU0_SA_CB<0>")
	)
	(arc
		(start 343.526618 -262.383016)
		(mid 343.252419 -262.307181)
		(end 342.975946 -262.37438)
		(width 0.088646)
		(layer "In6.Cu")
		(net "M_C_CPU0_SA_CB<0>")
	)
	(arc
		(start 336.007964 -262.383016)
		(mid 335.725262 -262.30724)
		(end 335.44256 -262.383016)
		(width 0.088646)
		(layer "In6.Cu")
		(net "M_C_CPU0_SA_CB<0>")
	)
	(arc
		(start 342.961214 -262.383016)
		(mid 342.774016 -262.433159)
		(end 342.586818 -262.383016)
		(width 0.088646)
		(layer "In6.Cu")
		(net "M_C_CPU0_SA_CB<0>")
	)
	(arc
		(start 344.083894 -262.116062)
		(mid 344.025738 -262.266175)
		(end 343.909904 -262.377936)
		(width 0.088646)
		(layer "In6.Cu")
		(net "M_C_CPU0_SA_CB<0>")
	)
	(arc
		(start 333.188564 -262.383016)
		(mid 332.905862 -262.30724)
		(end 332.62316 -262.383016)
		(width 0.088646)
		(layer "In6.Cu")
		(net "M_C_CPU0_SA_CB<0>")
	)
	(arc
		(start 337.32216 -262.383016)
		(mid 337.134962 -262.433159)
		(end 336.947764 -262.383016)
		(width 0.088646)
		(layer "In6.Cu")
		(net "M_C_CPU0_SA_CB<0>")
	)
	(arc
		(start 335.44256 -262.383016)
		(mid 335.255362 -262.433159)
		(end 335.068164 -262.383016)
		(width 0.088646)
		(layer "In6.Cu")
		(net "M_C_CPU0_SA_CB<0>")
	)
	(arc
		(start 341.647018 -262.383016)
		(mid 341.372819 -262.307181)
		(end 341.096346 -262.37438)
		(width 0.088646)
		(layer "In6.Cu")
		(net "M_C_CPU0_SA_CB<0>")
	)
	(segment
		(start 273.218148 -261.278116)
		(end 272.713704 -261.278116)
		(width 0.20066)
		(layer "F.Cu")
		(net "M_C_CPU0_SA_CA<6>")
	)
	(segment
		(start 274.152868 -260.641846)
		(end 274.143978 -260.632956)
		(width 0.1016)
		(layer "F.Cu")
		(net "M_C_CPU0_SA_CA<6>")
	)
	(segment
		(start 273.37258 -261.123684)
		(end 273.218148 -261.278116)
		(width 0.20066)
		(layer "F.Cu")
		(net "M_C_CPU0_SA_CA<6>")
	)
	(segment
		(start 277.072598 -261.066788)
		(end 276.647656 -260.641846)
		(width 0.20066)
		(layer "F.Cu")
		(net "M_C_CPU0_SA_CA<6>")
	)
	(segment
		(start 276.647656 -260.641846)
		(end 276.469094 -260.641846)
		(width 0.20066)
		(layer "F.Cu")
		(net "M_C_CPU0_SA_CA<6>")
	)
	(segment
		(start 276.138386 -260.641846)
		(end 274.152868 -260.641846)
		(width 0.1016)
		(layer "F.Cu")
		(net "M_C_CPU0_SA_CA<6>")
	)
	(segment
		(start 340.424516 -254.733298)
		(end 340.424262 -254.733552)
		(width 0.20066)
		(layer "F.Cu")
		(net "M_C_CPU0_SA_CA<6>")
	)
	(segment
		(start 272.713704 -261.278116)
		(end 272.502376 -261.066788)
		(width 0.20066)
		(layer "F.Cu")
		(net "M_C_CPU0_SA_CA<6>")
	)
	(segment
		(start 272.502376 -261.066788)
		(end 271.168114 -261.066788)
		(width 0.20066)
		(layer "F.Cu")
		(net "M_C_CPU0_SA_CA<6>")
	)
	(segment
		(start 278.711914 -261.066788)
		(end 277.072598 -261.066788)
		(width 0.20066)
		(layer "F.Cu")
		(net "M_C_CPU0_SA_CA<6>")
	)
	(segment
		(start 273.53514 -260.632956)
		(end 273.37258 -260.795516)
		(width 0.20066)
		(layer "F.Cu")
		(net "M_C_CPU0_SA_CA<6>")
	)
	(segment
		(start 279.816814 -261.066788)
		(end 278.711914 -261.066788)
		(width 0.20066)
		(layer "F.Cu")
		(net "M_C_CPU0_SA_CA<6>")
	)
	(segment
		(start 340.424516 -254.197612)
		(end 340.424516 -254.733298)
		(width 0.20066)
		(layer "F.Cu")
		(net "M_C_CPU0_SA_CA<6>")
	)
	(segment
		(start 274.143978 -260.632956)
		(end 273.53514 -260.632956)
		(width 0.20066)
		(layer "F.Cu")
		(net "M_C_CPU0_SA_CA<6>")
	)
	(segment
		(start 276.469094 -260.641846)
		(end 276.138386 -260.641846)
		(width 0.101854)
		(layer "F.Cu")
		(net "M_C_CPU0_SA_CA<6>")
	)
	(segment
		(start 273.37258 -260.795516)
		(end 273.37258 -261.123684)
		(width 0.20066)
		(layer "F.Cu")
		(net "M_C_CPU0_SA_CA<6>")
	)
	(segment
		(start 306.376578 -257.967226)
		(end 305.40198 -258.941824)
		(width 0.18288)
		(layer "In4.Cu")
		(net "M_C_CPU0_SA_CA<6>")
	)
	(segment
		(start 332.375002 -253.52121)
		(end 330.641452 -253.52121)
		(width 0.18288)
		(layer "In4.Cu")
		(net "M_C_CPU0_SA_CA<6>")
	)
	(segment
		(start 315.108336 -257.966972)
		(end 313.866276 -257.966972)
		(width 0.18288)
		(layer "In4.Cu")
		(net "M_C_CPU0_SA_CA<6>")
	)
	(segment
		(start 303.552098 -258.602226)
		(end 303.200816 -258.602226)
		(width 0.18288)
		(layer "In4.Cu")
		(net "M_C_CPU0_SA_CA<6>")
	)
	(segment
		(start 289.828732 -259.649976)
		(end 287.293304 -259.649976)
		(width 0.18288)
		(layer "In4.Cu")
		(net "M_C_CPU0_SA_CA<6>")
	)
	(segment
		(start 292.153848 -260.194552)
		(end 291.706554 -260.641846)
		(width 0.18288)
		(layer "In4.Cu")
		(net "M_C_CPU0_SA_CA<6>")
	)
	(segment
		(start 302.861218 -258.941824)
		(end 298.024296 -258.941824)
		(width 0.18288)
		(layer "In4.Cu")
		(net "M_C_CPU0_SA_CA<6>")
	)
	(segment
		(start 303.200816 -258.602226)
		(end 302.861218 -258.941824)
		(width 0.18288)
		(layer "In4.Cu")
		(net "M_C_CPU0_SA_CA<6>")
	)
	(segment
		(start 328.326242 -255.83642)
		(end 320.25209 -255.83642)
		(width 0.18288)
		(layer "In4.Cu")
		(net "M_C_CPU0_SA_CA<6>")
	)
	(segment
		(start 284.101286 -261.49173)
		(end 280.241756 -261.49173)
		(width 0.18288)
		(layer "In4.Cu")
		(net "M_C_CPU0_SA_CA<6>")
	)
	(segment
		(start 284.41904 -261.173976)
		(end 284.101286 -261.49173)
		(width 0.18288)
		(layer "In4.Cu")
		(net "M_C_CPU0_SA_CA<6>")
	)
	(segment
		(start 287.293304 -259.649976)
		(end 285.769304 -261.173976)
		(width 0.18288)
		(layer "In4.Cu")
		(net "M_C_CPU0_SA_CA<6>")
	)
	(segment
		(start 291.706554 -260.641846)
		(end 290.820602 -260.641846)
		(width 0.18288)
		(layer "In4.Cu")
		(net "M_C_CPU0_SA_CA<6>")
	)
	(segment
		(start 298.024296 -258.941824)
		(end 297.174412 -259.791708)
		(width 0.18288)
		(layer "In4.Cu")
		(net "M_C_CPU0_SA_CA<6>")
	)
	(segment
		(start 290.820602 -260.641846)
		(end 289.828732 -259.649976)
		(width 0.18288)
		(layer "In4.Cu")
		(net "M_C_CPU0_SA_CA<6>")
	)
	(segment
		(start 285.769304 -261.173976)
		(end 284.41904 -261.173976)
		(width 0.18288)
		(layer "In4.Cu")
		(net "M_C_CPU0_SA_CA<6>")
	)
	(segment
		(start 297.174412 -259.791708)
		(end 292.432994 -259.791708)
		(width 0.18288)
		(layer "In4.Cu")
		(net "M_C_CPU0_SA_CA<6>")
	)
	(segment
		(start 303.891696 -258.941824)
		(end 303.552098 -258.602226)
		(width 0.18288)
		(layer "In4.Cu")
		(net "M_C_CPU0_SA_CA<6>")
	)
	(segment
		(start 313.866276 -257.966972)
		(end 313.866022 -257.967226)
		(width 0.18288)
		(layer "In4.Cu")
		(net "M_C_CPU0_SA_CA<6>")
	)
	(segment
		(start 338.746592 -254.417576)
		(end 338.73186 -254.409194)
		(width 0.088646)
		(layer "In4.Cu")
		(net "M_C_CPU0_SA_CA<6>")
	)
	(segment
		(start 338.746846 -254.41783)
		(end 338.746592 -254.417576)
		(width 0.088646)
		(layer "In4.Cu")
		(net "M_C_CPU0_SA_CA<6>")
	)
	(segment
		(start 333.915766 -254.319532)
		(end 333.117444 -253.52121)
		(width 0.088646)
		(layer "In4.Cu")
		(net "M_C_CPU0_SA_CA<6>")
	)
	(segment
		(start 292.432994 -259.791708)
		(end 292.153848 -260.070854)
		(width 0.18288)
		(layer "In4.Cu")
		(net "M_C_CPU0_SA_CA<6>")
	)
	(segment
		(start 292.153848 -260.070854)
		(end 292.153848 -260.194552)
		(width 0.18288)
		(layer "In4.Cu")
		(net "M_C_CPU0_SA_CA<6>")
	)
	(segment
		(start 305.40198 -258.941824)
		(end 303.891696 -258.941824)
		(width 0.18288)
		(layer "In4.Cu")
		(net "M_C_CPU0_SA_CA<6>")
	)
	(segment
		(start 330.641452 -253.52121)
		(end 328.326242 -255.83642)
		(width 0.18288)
		(layer "In4.Cu")
		(net "M_C_CPU0_SA_CA<6>")
	)
	(segment
		(start 313.866022 -257.967226)
		(end 306.376578 -257.967226)
		(width 0.18288)
		(layer "In4.Cu")
		(net "M_C_CPU0_SA_CA<6>")
	)
	(segment
		(start 320.25209 -255.83642)
		(end 315.108336 -257.966972)
		(width 0.18288)
		(layer "In4.Cu")
		(net "M_C_CPU0_SA_CA<6>")
	)
	(segment
		(start 340.053422 -254.632968)
		(end 339.671914 -254.409194)
		(width 0.088646)
		(layer "In4.Cu")
		(net "M_C_CPU0_SA_CA<6>")
	)
	(segment
		(start 333.117444 -253.52121)
		(end 332.375002 -253.52121)
		(width 0.088646)
		(layer "In4.Cu")
		(net "M_C_CPU0_SA_CA<6>")
	)
	(segment
		(start 280.241756 -261.49173)
		(end 279.816814 -261.066788)
		(width 0.18288)
		(layer "In4.Cu")
		(net "M_C_CPU0_SA_CA<6>")
	)
	(arc
		(start 337.79206 -254.409194)
		(mid 337.604862 -254.359051)
		(end 337.417664 -254.409194)
		(width 0.088646)
		(layer "In4.Cu")
		(net "M_C_CPU0_SA_CA<6>")
	)
	(arc
		(start 337.417664 -254.409194)
		(mid 337.134962 -254.48497)
		(end 336.85226 -254.409194)
		(width 0.088646)
		(layer "In4.Cu")
		(net "M_C_CPU0_SA_CA<6>")
	)
	(arc
		(start 335.91246 -254.409194)
		(mid 335.725262 -254.359051)
		(end 335.538064 -254.409194)
		(width 0.088646)
		(layer "In4.Cu")
		(net "M_C_CPU0_SA_CA<6>")
	)
	(arc
		(start 336.85226 -254.409194)
		(mid 336.665062 -254.359051)
		(end 336.477864 -254.409194)
		(width 0.088646)
		(layer "In4.Cu")
		(net "M_C_CPU0_SA_CA<6>")
	)
	(arc
		(start 336.477864 -254.409194)
		(mid 336.195162 -254.48497)
		(end 335.91246 -254.409194)
		(width 0.088646)
		(layer "In4.Cu")
		(net "M_C_CPU0_SA_CA<6>")
	)
	(arc
		(start 338.357464 -254.409194)
		(mid 338.074762 -254.48497)
		(end 337.79206 -254.409194)
		(width 0.088646)
		(layer "In4.Cu")
		(net "M_C_CPU0_SA_CA<6>")
	)
	(arc
		(start 334.03286 -254.409194)
		(mid 333.971382 -254.368192)
		(end 333.915766 -254.319532)
		(width 0.088646)
		(layer "In4.Cu")
		(net "M_C_CPU0_SA_CA<6>")
	)
	(arc
		(start 334.97266 -254.409194)
		(mid 334.785462 -254.359051)
		(end 334.598264 -254.409194)
		(width 0.088646)
		(layer "In4.Cu")
		(net "M_C_CPU0_SA_CA<6>")
	)
	(arc
		(start 338.73186 -254.409194)
		(mid 338.544662 -254.359051)
		(end 338.357464 -254.409194)
		(width 0.088646)
		(layer "In4.Cu")
		(net "M_C_CPU0_SA_CA<6>")
	)
	(arc
		(start 335.538064 -254.409194)
		(mid 335.255362 -254.48497)
		(end 334.97266 -254.409194)
		(width 0.088646)
		(layer "In4.Cu")
		(net "M_C_CPU0_SA_CA<6>")
	)
	(arc
		(start 334.598264 -254.409194)
		(mid 334.315562 -254.48497)
		(end 334.03286 -254.409194)
		(width 0.088646)
		(layer "In4.Cu")
		(net "M_C_CPU0_SA_CA<6>")
	)
	(arc
		(start 339.297518 -254.409194)
		(mid 339.023319 -254.485029)
		(end 338.746846 -254.41783)
		(width 0.088646)
		(layer "In4.Cu")
		(net "M_C_CPU0_SA_CA<6>")
	)
	(arc
		(start 340.424262 -254.733552)
		(mid 340.232132 -254.707995)
		(end 340.053422 -254.632968)
		(width 0.088646)
		(layer "In4.Cu")
		(net "M_C_CPU0_SA_CA<6>")
	)
	(arc
		(start 339.671914 -254.409194)
		(mid 339.484716 -254.359051)
		(end 339.297518 -254.409194)
		(width 0.088646)
		(layer "In4.Cu")
		(net "M_C_CPU0_SA_CA<6>")
	)
	(segment
		(start 277.091394 -262.213344)
		(end 277.091394 -262.042656)
		(width 0.20066)
		(layer "F.Cu")
		(net "M_C_CPU0_SA_CA<5>")
	)
	(segment
		(start 277.233888 -262.355838)
		(end 277.091394 -262.213344)
		(width 0.20066)
		(layer "F.Cu")
		(net "M_C_CPU0_SA_CA<5>")
	)
	(segment
		(start 341.364316 -256.361184)
		(end 341.364062 -256.361438)
		(width 0.20066)
		(layer "F.Cu")
		(net "M_C_CPU0_SA_CA<5>")
	)
	(segment
		(start 283.916882 -261.916672)
		(end 282.811982 -261.916672)
		(width 0.20066)
		(layer "F.Cu")
		(net "M_C_CPU0_SA_CA<5>")
	)
	(segment
		(start 280.606246 -262.192516)
		(end 280.457148 -262.341614)
		(width 0.20066)
		(layer "F.Cu")
		(net "M_C_CPU0_SA_CA<5>")
	)
	(segment
		(start 282.811982 -261.916672)
		(end 281.99588 -261.916672)
		(width 0.20066)
		(layer "F.Cu")
		(net "M_C_CPU0_SA_CA<5>")
	)
	(segment
		(start 281.788362 -262.12419)
		(end 281.34183 -262.12419)
		(width 0.20066)
		(layer "F.Cu")
		(net "M_C_CPU0_SA_CA<5>")
	)
	(segment
		(start 279.912826 -262.341614)
		(end 277.839932 -262.341614)
		(width 0.1016)
		(layer "F.Cu")
		(net "M_C_CPU0_SA_CA<5>")
	)
	(segment
		(start 276.96541 -261.916672)
		(end 275.268182 -261.916672)
		(width 0.20066)
		(layer "F.Cu")
		(net "M_C_CPU0_SA_CA<5>")
	)
	(segment
		(start 277.58771 -262.355838)
		(end 277.233888 -262.355838)
		(width 0.20066)
		(layer "F.Cu")
		(net "M_C_CPU0_SA_CA<5>")
	)
	(segment
		(start 281.34183 -262.12419)
		(end 281.129994 -261.912354)
		(width 0.20066)
		(layer "F.Cu")
		(net "M_C_CPU0_SA_CA<5>")
	)
	(segment
		(start 280.73477 -261.912354)
		(end 280.606246 -262.040878)
		(width 0.20066)
		(layer "F.Cu")
		(net "M_C_CPU0_SA_CA<5>")
	)
	(segment
		(start 280.606246 -262.040878)
		(end 280.606246 -262.192516)
		(width 0.20066)
		(layer "F.Cu")
		(net "M_C_CPU0_SA_CA<5>")
	)
	(segment
		(start 277.839932 -262.341614)
		(end 277.601934 -262.341614)
		(width 0.101854)
		(layer "F.Cu")
		(net "M_C_CPU0_SA_CA<5>")
	)
	(segment
		(start 281.129994 -261.912354)
		(end 280.73477 -261.912354)
		(width 0.20066)
		(layer "F.Cu")
		(net "M_C_CPU0_SA_CA<5>")
	)
	(segment
		(start 277.091394 -262.042656)
		(end 276.96541 -261.916672)
		(width 0.20066)
		(layer "F.Cu")
		(net "M_C_CPU0_SA_CA<5>")
	)
	(segment
		(start 277.601934 -262.341614)
		(end 277.58771 -262.355838)
		(width 0.101854)
		(layer "F.Cu")
		(net "M_C_CPU0_SA_CA<5>")
	)
	(segment
		(start 341.364316 -255.825498)
		(end 341.364316 -256.361184)
		(width 0.20066)
		(layer "F.Cu")
		(net "M_C_CPU0_SA_CA<5>")
	)
	(segment
		(start 281.99588 -261.916672)
		(end 281.788362 -262.12419)
		(width 0.20066)
		(layer "F.Cu")
		(net "M_C_CPU0_SA_CA<5>")
	)
	(segment
		(start 280.457148 -262.341614)
		(end 279.912826 -262.341614)
		(width 0.20066)
		(layer "F.Cu")
		(net "M_C_CPU0_SA_CA<5>")
	)
	(segment
		(start 291.702744 -261.54888)
		(end 290.438332 -261.54888)
		(width 0.18288)
		(layer "In4.Cu")
		(net "M_C_CPU0_SA_CA<5>")
	)
	(segment
		(start 292.609778 -260.641846)
		(end 291.702744 -261.54888)
		(width 0.18288)
		(layer "In4.Cu")
		(net "M_C_CPU0_SA_CA<5>")
	)
	(segment
		(start 340.519766 -255.547622)
		(end 340.519766 -255.540002)
		(width 0.088646)
		(layer "In4.Cu")
		(net "M_C_CPU0_SA_CA<5>")
	)
	(segment
		(start 308.385464 -259.396992)
		(end 308.202584 -259.579872)
		(width 0.18288)
		(layer "In4.Cu")
		(net "M_C_CPU0_SA_CA<5>")
	)
	(segment
		(start 311.184036 -259.008626)
		(end 310.61279 -259.579872)
		(width 0.18288)
		(layer "In4.Cu")
		(net "M_C_CPU0_SA_CA<5>")
	)
	(segment
		(start 340.707218 -255.87198)
		(end 340.698328 -255.8669)
		(width 0.088646)
		(layer "In4.Cu")
		(net "M_C_CPU0_SA_CA<5>")
	)
	(segment
		(start 309.259224 -259.579872)
		(end 309.076344 -259.396992)
		(width 0.18288)
		(layer "In4.Cu")
		(net "M_C_CPU0_SA_CA<5>")
	)
	(segment
		(start 333.580486 -254.998728)
		(end 332.600808 -254.01905)
		(width 0.088646)
		(layer "In4.Cu")
		(net "M_C_CPU0_SA_CA<5>")
	)
	(segment
		(start 302.110648 -259.579872)
		(end 301.048674 -260.641846)
		(width 0.18288)
		(layer "In4.Cu")
		(net "M_C_CPU0_SA_CA<5>")
	)
	(segment
		(start 284.330648 -261.916672)
		(end 283.916882 -261.916672)
		(width 0.18288)
		(layer "In4.Cu")
		(net "M_C_CPU0_SA_CA<5>")
	)
	(segment
		(start 310.61279 -259.579872)
		(end 309.259224 -259.579872)
		(width 0.18288)
		(layer "In4.Cu")
		(net "M_C_CPU0_SA_CA<5>")
	)
	(segment
		(start 332.375002 -254.01905)
		(end 330.847954 -254.01905)
		(width 0.18288)
		(layer "In4.Cu")
		(net "M_C_CPU0_SA_CA<5>")
	)
	(segment
		(start 328.695304 -256.1717)
		(end 320.969132 -256.1717)
		(width 0.18288)
		(layer "In4.Cu")
		(net "M_C_CPU0_SA_CA<5>")
	)
	(segment
		(start 287.035748 -260.696202)
		(end 285.393638 -262.338312)
		(width 0.18288)
		(layer "In4.Cu")
		(net "M_C_CPU0_SA_CA<5>")
	)
	(segment
		(start 308.202584 -259.579872)
		(end 302.110648 -259.579872)
		(width 0.18288)
		(layer "In4.Cu")
		(net "M_C_CPU0_SA_CA<5>")
	)
	(segment
		(start 290.438332 -261.54888)
		(end 289.258248 -260.368796)
		(width 0.18288)
		(layer "In4.Cu")
		(net "M_C_CPU0_SA_CA<5>")
	)
	(segment
		(start 320.969132 -256.1717)
		(end 314.120276 -259.008626)
		(width 0.18288)
		(layer "In4.Cu")
		(net "M_C_CPU0_SA_CA<5>")
	)
	(segment
		(start 301.048674 -260.641846)
		(end 292.609778 -260.641846)
		(width 0.18288)
		(layer "In4.Cu")
		(net "M_C_CPU0_SA_CA<5>")
	)
	(segment
		(start 339.297518 -255.05791)
		(end 339.287104 -255.051814)
		(width 0.088646)
		(layer "In4.Cu")
		(net "M_C_CPU0_SA_CA<5>")
	)
	(segment
		(start 308.568344 -258.551426)
		(end 308.385464 -258.734306)
		(width 0.18288)
		(layer "In4.Cu")
		(net "M_C_CPU0_SA_CA<5>")
	)
	(segment
		(start 308.893464 -258.551426)
		(end 308.568344 -258.551426)
		(width 0.18288)
		(layer "In4.Cu")
		(net "M_C_CPU0_SA_CA<5>")
	)
	(segment
		(start 289.258248 -260.368796)
		(end 287.985708 -260.368796)
		(width 0.18288)
		(layer "In4.Cu")
		(net "M_C_CPU0_SA_CA<5>")
	)
	(segment
		(start 341.364062 -256.361438)
		(end 341.051388 -256.361438)
		(width 0.088646)
		(layer "In4.Cu")
		(net "M_C_CPU0_SA_CA<5>")
	)
	(segment
		(start 330.847954 -254.01905)
		(end 328.695304 -256.1717)
		(width 0.18288)
		(layer "In4.Cu")
		(net "M_C_CPU0_SA_CA<5>")
	)
	(segment
		(start 309.076344 -259.396992)
		(end 309.076344 -258.734306)
		(width 0.18288)
		(layer "In4.Cu")
		(net "M_C_CPU0_SA_CA<5>")
	)
	(segment
		(start 337.417664 -255.05791)
		(end 337.402932 -255.049274)
		(width 0.088646)
		(layer "In4.Cu")
		(net "M_C_CPU0_SA_CA<5>")
	)
	(segment
		(start 332.600808 -254.01905)
		(end 332.375002 -254.01905)
		(width 0.088646)
		(layer "In4.Cu")
		(net "M_C_CPU0_SA_CA<5>")
	)
	(segment
		(start 341.051388 -256.361438)
		(end 340.985856 -256.295906)
		(width 0.088646)
		(layer "In4.Cu")
		(net "M_C_CPU0_SA_CA<5>")
	)
	(segment
		(start 284.752288 -262.338312)
		(end 284.330648 -261.916672)
		(width 0.18288)
		(layer "In4.Cu")
		(net "M_C_CPU0_SA_CA<5>")
	)
	(segment
		(start 287.658302 -260.696202)
		(end 287.035748 -260.696202)
		(width 0.18288)
		(layer "In4.Cu")
		(net "M_C_CPU0_SA_CA<5>")
	)
	(segment
		(start 309.076344 -258.734306)
		(end 308.893464 -258.551426)
		(width 0.18288)
		(layer "In4.Cu")
		(net "M_C_CPU0_SA_CA<5>")
	)
	(segment
		(start 339.682328 -255.051814)
		(end 339.671914 -255.05791)
		(width 0.088646)
		(layer "In4.Cu")
		(net "M_C_CPU0_SA_CA<5>")
	)
	(segment
		(start 285.393638 -262.338312)
		(end 284.752288 -262.338312)
		(width 0.18288)
		(layer "In4.Cu")
		(net "M_C_CPU0_SA_CA<5>")
	)
	(segment
		(start 314.120276 -259.008626)
		(end 311.184036 -259.008626)
		(width 0.18288)
		(layer "In4.Cu")
		(net "M_C_CPU0_SA_CA<5>")
	)
	(segment
		(start 287.985708 -260.368796)
		(end 287.658302 -260.696202)
		(width 0.18288)
		(layer "In4.Cu")
		(net "M_C_CPU0_SA_CA<5>")
	)
	(segment
		(start 308.385464 -258.734306)
		(end 308.385464 -259.396992)
		(width 0.18288)
		(layer "In4.Cu")
		(net "M_C_CPU0_SA_CA<5>")
	)
	(arc
		(start 336.477864 -255.05791)
		(mid 336.195162 -254.982168)
		(end 335.91246 -255.05791)
		(width 0.088646)
		(layer "In4.Cu")
		(net "M_C_CPU0_SA_CA<5>")
	)
	(arc
		(start 340.698328 -255.8669)
		(mid 340.567414 -255.73054)
		(end 340.519766 -255.547622)
		(width 0.088646)
		(layer "In4.Cu")
		(net "M_C_CPU0_SA_CA<5>")
	)
	(arc
		(start 337.402932 -255.049274)
		(mid 337.126491 -254.982108)
		(end 336.85226 -255.05791)
		(width 0.088646)
		(layer "In4.Cu")
		(net "M_C_CPU0_SA_CA<5>")
	)
	(arc
		(start 334.598264 -255.05791)
		(mid 334.315562 -254.982168)
		(end 334.03286 -255.05791)
		(width 0.088646)
		(layer "In4.Cu")
		(net "M_C_CPU0_SA_CA<5>")
	)
	(arc
		(start 339.287104 -255.051814)
		(mid 339.008672 -254.982)
		(end 338.73186 -255.05791)
		(width 0.088646)
		(layer "In4.Cu")
		(net "M_C_CPU0_SA_CA<5>")
	)
	(arc
		(start 340.237064 -255.05791)
		(mid 339.960505 -254.982201)
		(end 339.682328 -255.051814)
		(width 0.088646)
		(layer "In4.Cu")
		(net "M_C_CPU0_SA_CA<5>")
	)
	(arc
		(start 340.519766 -255.540002)
		(mid 340.442137 -255.261589)
		(end 340.237064 -255.05791)
		(width 0.088646)
		(layer "In4.Cu")
		(net "M_C_CPU0_SA_CA<5>")
	)
	(arc
		(start 333.658464 -255.05791)
		(mid 333.617534 -255.030877)
		(end 333.580486 -254.998728)
		(width 0.088646)
		(layer "In4.Cu")
		(net "M_C_CPU0_SA_CA<5>")
	)
	(arc
		(start 340.985856 -256.295906)
		(mid 340.896768 -256.050921)
		(end 340.707218 -255.87198)
		(width 0.088646)
		(layer "In4.Cu")
		(net "M_C_CPU0_SA_CA<5>")
	)
	(arc
		(start 338.357464 -255.05791)
		(mid 338.074762 -254.982168)
		(end 337.79206 -255.05791)
		(width 0.088646)
		(layer "In4.Cu")
		(net "M_C_CPU0_SA_CA<5>")
	)
	(arc
		(start 336.85226 -255.05791)
		(mid 336.665062 -255.108053)
		(end 336.477864 -255.05791)
		(width 0.088646)
		(layer "In4.Cu")
		(net "M_C_CPU0_SA_CA<5>")
	)
	(arc
		(start 335.91246 -255.05791)
		(mid 335.725262 -255.108053)
		(end 335.538064 -255.05791)
		(width 0.088646)
		(layer "In4.Cu")
		(net "M_C_CPU0_SA_CA<5>")
	)
	(arc
		(start 334.03286 -255.05791)
		(mid 333.845662 -255.108053)
		(end 333.658464 -255.05791)
		(width 0.088646)
		(layer "In4.Cu")
		(net "M_C_CPU0_SA_CA<5>")
	)
	(arc
		(start 338.73186 -255.05791)
		(mid 338.544662 -255.108053)
		(end 338.357464 -255.05791)
		(width 0.088646)
		(layer "In4.Cu")
		(net "M_C_CPU0_SA_CA<5>")
	)
	(arc
		(start 337.79206 -255.05791)
		(mid 337.604862 -255.108053)
		(end 337.417664 -255.05791)
		(width 0.088646)
		(layer "In4.Cu")
		(net "M_C_CPU0_SA_CA<5>")
	)
	(arc
		(start 334.97266 -255.05791)
		(mid 334.785462 -255.108053)
		(end 334.598264 -255.05791)
		(width 0.088646)
		(layer "In4.Cu")
		(net "M_C_CPU0_SA_CA<5>")
	)
	(arc
		(start 335.538064 -255.05791)
		(mid 335.255362 -254.982168)
		(end 334.97266 -255.05791)
		(width 0.088646)
		(layer "In4.Cu")
		(net "M_C_CPU0_SA_CA<5>")
	)
	(arc
		(start 339.671914 -255.05791)
		(mid 339.484716 -255.108053)
		(end 339.297518 -255.05791)
		(width 0.088646)
		(layer "In4.Cu")
		(net "M_C_CPU0_SA_CA<5>")
	)
	(segment
		(start 276.469094 -262.341868)
		(end 276.138386 -262.341868)
		(width 0.101854)
		(layer "F.Cu")
		(net "M_C_CPU0_SA_CA<4>")
	)
	(segment
		(start 272.713704 -262.978138)
		(end 272.502376 -262.76681)
		(width 0.20066)
		(layer "F.Cu")
		(net "M_C_CPU0_SA_CA<4>")
	)
	(segment
		(start 276.138386 -262.341868)
		(end 274.152868 -262.341868)
		(width 0.1016)
		(layer "F.Cu")
		(net "M_C_CPU0_SA_CA<4>")
	)
	(segment
		(start 279.816814 -262.76681)
		(end 278.711914 -262.76681)
		(width 0.20066)
		(layer "F.Cu")
		(net "M_C_CPU0_SA_CA<4>")
	)
	(segment
		(start 273.53514 -262.332978)
		(end 273.37258 -262.495538)
		(width 0.20066)
		(layer "F.Cu")
		(net "M_C_CPU0_SA_CA<4>")
	)
	(segment
		(start 340.424516 -255.825498)
		(end 340.424516 -256.361184)
		(width 0.20066)
		(layer "F.Cu")
		(net "M_C_CPU0_SA_CA<4>")
	)
	(segment
		(start 274.152868 -262.341868)
		(end 274.143978 -262.332978)
		(width 0.1016)
		(layer "F.Cu")
		(net "M_C_CPU0_SA_CA<4>")
	)
	(segment
		(start 273.37258 -262.495538)
		(end 273.37258 -262.823706)
		(width 0.20066)
		(layer "F.Cu")
		(net "M_C_CPU0_SA_CA<4>")
	)
	(segment
		(start 274.143978 -262.332978)
		(end 273.53514 -262.332978)
		(width 0.20066)
		(layer "F.Cu")
		(net "M_C_CPU0_SA_CA<4>")
	)
	(segment
		(start 273.37258 -262.823706)
		(end 273.218148 -262.978138)
		(width 0.20066)
		(layer "F.Cu")
		(net "M_C_CPU0_SA_CA<4>")
	)
	(segment
		(start 340.424516 -256.361184)
		(end 340.424262 -256.361438)
		(width 0.20066)
		(layer "F.Cu")
		(net "M_C_CPU0_SA_CA<4>")
	)
	(segment
		(start 273.218148 -262.978138)
		(end 272.713704 -262.978138)
		(width 0.20066)
		(layer "F.Cu")
		(net "M_C_CPU0_SA_CA<4>")
	)
	(segment
		(start 277.072598 -262.76681)
		(end 276.647656 -262.341868)
		(width 0.20066)
		(layer "F.Cu")
		(net "M_C_CPU0_SA_CA<4>")
	)
	(segment
		(start 272.502376 -262.76681)
		(end 271.168114 -262.76681)
		(width 0.20066)
		(layer "F.Cu")
		(net "M_C_CPU0_SA_CA<4>")
	)
	(segment
		(start 276.647656 -262.341868)
		(end 276.469094 -262.341868)
		(width 0.20066)
		(layer "F.Cu")
		(net "M_C_CPU0_SA_CA<4>")
	)
	(segment
		(start 278.711914 -262.76681)
		(end 277.072598 -262.76681)
		(width 0.20066)
		(layer "F.Cu")
		(net "M_C_CPU0_SA_CA<4>")
	)
	(segment
		(start 303.655222 -260.123178)
		(end 302.28667 -261.49173)
		(width 0.18288)
		(layer "In4.Cu")
		(net "M_C_CPU0_SA_CA<4>")
	)
	(segment
		(start 333.445866 -255.133348)
		(end 332.829408 -254.51689)
		(width 0.088646)
		(layer "In4.Cu")
		(net "M_C_CPU0_SA_CA<4>")
	)
	(segment
		(start 338.272374 -255.22936)
		(end 338.26196 -255.223264)
		(width 0.088646)
		(layer "In4.Cu")
		(net "M_C_CPU0_SA_CA<4>")
	)
	(segment
		(start 337.332828 -255.22936)
		(end 337.322414 -255.223264)
		(width 0.088646)
		(layer "In4.Cu")
		(net "M_C_CPU0_SA_CA<4>")
	)
	(segment
		(start 291.886894 -262.107426)
		(end 288.521648 -262.107426)
		(width 0.18288)
		(layer "In4.Cu")
		(net "M_C_CPU0_SA_CA<4>")
	)
	(segment
		(start 286.4739 -262.466328)
		(end 285.747968 -263.19226)
		(width 0.18288)
		(layer "In4.Cu")
		(net "M_C_CPU0_SA_CA<4>")
	)
	(segment
		(start 285.747968 -263.19226)
		(end 283.614368 -263.19226)
		(width 0.18288)
		(layer "In4.Cu")
		(net "M_C_CPU0_SA_CA<4>")
	)
	(segment
		(start 287.710118 -261.295896)
		(end 287.168082 -261.295896)
		(width 0.18288)
		(layer "In4.Cu")
		(net "M_C_CPU0_SA_CA<4>")
	)
	(segment
		(start 282.763976 -262.341868)
		(end 280.241756 -262.341868)
		(width 0.18288)
		(layer "In4.Cu")
		(net "M_C_CPU0_SA_CA<4>")
	)
	(segment
		(start 314.226956 -259.516626)
		(end 311.483756 -259.516626)
		(width 0.18288)
		(layer "In4.Cu")
		(net "M_C_CPU0_SA_CA<4>")
	)
	(segment
		(start 283.614368 -263.19226)
		(end 282.763976 -262.341868)
		(width 0.18288)
		(layer "In4.Cu")
		(net "M_C_CPU0_SA_CA<4>")
	)
	(segment
		(start 292.50259 -261.49173)
		(end 291.886894 -262.107426)
		(width 0.18288)
		(layer "In4.Cu")
		(net "M_C_CPU0_SA_CA<4>")
	)
	(segment
		(start 332.375002 -254.51689)
		(end 331.054456 -254.51689)
		(width 0.18288)
		(layer "In4.Cu")
		(net "M_C_CPU0_SA_CA<4>")
	)
	(segment
		(start 340.61146 -256.03708)
		(end 340.605364 -256.033524)
		(width 0.088646)
		(layer "In4.Cu")
		(net "M_C_CPU0_SA_CA<4>")
	)
	(segment
		(start 288.521648 -262.107426)
		(end 287.710118 -261.295896)
		(width 0.18288)
		(layer "In4.Cu")
		(net "M_C_CPU0_SA_CA<4>")
	)
	(segment
		(start 340.736936 -256.361438)
		(end 340.79434 -256.304034)
		(width 0.088646)
		(layer "In4.Cu")
		(net "M_C_CPU0_SA_CA<4>")
	)
	(segment
		(start 307.311298 -260.707378)
		(end 306.727098 -260.123178)
		(width 0.18288)
		(layer "In4.Cu")
		(net "M_C_CPU0_SA_CA<4>")
	)
	(segment
		(start 339.767164 -255.223264)
		(end 339.75675 -255.22936)
		(width 0.088646)
		(layer "In4.Cu")
		(net "M_C_CPU0_SA_CA<4>")
	)
	(segment
		(start 286.4739 -261.990078)
		(end 286.4739 -262.466328)
		(width 0.18288)
		(layer "In4.Cu")
		(net "M_C_CPU0_SA_CA<4>")
	)
	(segment
		(start 310.293004 -260.707378)
		(end 307.311298 -260.707378)
		(width 0.18288)
		(layer "In4.Cu")
		(net "M_C_CPU0_SA_CA<4>")
	)
	(segment
		(start 336.392774 -255.22936)
		(end 336.38236 -255.223264)
		(width 0.088646)
		(layer "In4.Cu")
		(net "M_C_CPU0_SA_CA<4>")
	)
	(segment
		(start 311.483756 -259.516626)
		(end 310.293004 -260.707378)
		(width 0.18288)
		(layer "In4.Cu")
		(net "M_C_CPU0_SA_CA<4>")
	)
	(segment
		(start 280.241756 -262.341868)
		(end 279.816814 -262.76681)
		(width 0.18288)
		(layer "In4.Cu")
		(net "M_C_CPU0_SA_CA<4>")
	)
	(segment
		(start 340.62035 -256.04216)
		(end 340.61146 -256.03708)
		(width 0.088646)
		(layer "In4.Cu")
		(net "M_C_CPU0_SA_CA<4>")
	)
	(segment
		(start 340.15045 -255.228344)
		(end 340.14156 -255.223264)
		(width 0.088646)
		(layer "In4.Cu")
		(net "M_C_CPU0_SA_CA<4>")
	)
	(segment
		(start 331.054456 -254.51689)
		(end 329.064366 -256.50698)
		(width 0.18288)
		(layer "In4.Cu")
		(net "M_C_CPU0_SA_CA<4>")
	)
	(segment
		(start 329.064366 -256.50698)
		(end 321.493134 -256.50698)
		(width 0.18288)
		(layer "In4.Cu")
		(net "M_C_CPU0_SA_CA<4>")
	)
	(segment
		(start 340.424262 -256.361438)
		(end 340.736936 -256.361438)
		(width 0.088646)
		(layer "In4.Cu")
		(net "M_C_CPU0_SA_CA<4>")
	)
	(segment
		(start 321.493134 -256.50698)
		(end 314.226956 -259.516626)
		(width 0.18288)
		(layer "In4.Cu")
		(net "M_C_CPU0_SA_CA<4>")
	)
	(segment
		(start 302.28667 -261.49173)
		(end 292.50259 -261.49173)
		(width 0.18288)
		(layer "In4.Cu")
		(net "M_C_CPU0_SA_CA<4>")
	)
	(segment
		(start 332.829408 -254.51689)
		(end 332.375002 -254.51689)
		(width 0.088646)
		(layer "In4.Cu")
		(net "M_C_CPU0_SA_CA<4>")
	)
	(segment
		(start 306.727098 -260.123178)
		(end 303.655222 -260.123178)
		(width 0.18288)
		(layer "In4.Cu")
		(net "M_C_CPU0_SA_CA<4>")
	)
	(segment
		(start 287.168082 -261.295896)
		(end 286.4739 -261.990078)
		(width 0.18288)
		(layer "In4.Cu")
		(net "M_C_CPU0_SA_CA<4>")
	)
	(arc
		(start 335.068164 -255.223264)
		(mid 334.785462 -255.299006)
		(end 334.50276 -255.223264)
		(width 0.088646)
		(layer "In4.Cu")
		(net "M_C_CPU0_SA_CA<4>")
	)
	(arc
		(start 340.14156 -255.223264)
		(mid 339.954362 -255.173121)
		(end 339.767164 -255.223264)
		(width 0.088646)
		(layer "In4.Cu")
		(net "M_C_CPU0_SA_CA<4>")
	)
	(arc
		(start 337.887564 -255.223264)
		(mid 337.611005 -255.298973)
		(end 337.332828 -255.22936)
		(width 0.088646)
		(layer "In4.Cu")
		(net "M_C_CPU0_SA_CA<4>")
	)
	(arc
		(start 340.329012 -255.547622)
		(mid 340.281333 -255.364722)
		(end 340.15045 -255.228344)
		(width 0.088646)
		(layer "In4.Cu")
		(net "M_C_CPU0_SA_CA<4>")
	)
	(arc
		(start 334.128364 -255.223264)
		(mid 333.771841 -255.294167)
		(end 333.445866 -255.133348)
		(width 0.088646)
		(layer "In4.Cu")
		(net "M_C_CPU0_SA_CA<4>")
	)
	(arc
		(start 340.605364 -256.033524)
		(mid 340.402951 -255.827111)
		(end 340.329012 -255.547622)
		(width 0.088646)
		(layer "In4.Cu")
		(net "M_C_CPU0_SA_CA<4>")
	)
	(arc
		(start 340.79434 -256.304034)
		(mid 340.736184 -256.153921)
		(end 340.62035 -256.04216)
		(width 0.088646)
		(layer "In4.Cu")
		(net "M_C_CPU0_SA_CA<4>")
	)
	(arc
		(start 338.26196 -255.223264)
		(mid 338.074762 -255.173121)
		(end 337.887564 -255.223264)
		(width 0.088646)
		(layer "In4.Cu")
		(net "M_C_CPU0_SA_CA<4>")
	)
	(arc
		(start 336.007964 -255.223264)
		(mid 335.725262 -255.299006)
		(end 335.44256 -255.223264)
		(width 0.088646)
		(layer "In4.Cu")
		(net "M_C_CPU0_SA_CA<4>")
	)
	(arc
		(start 337.322414 -255.223264)
		(mid 337.135216 -255.173121)
		(end 336.948018 -255.223264)
		(width 0.088646)
		(layer "In4.Cu")
		(net "M_C_CPU0_SA_CA<4>")
	)
	(arc
		(start 336.38236 -255.223264)
		(mid 336.195162 -255.173121)
		(end 336.007964 -255.223264)
		(width 0.088646)
		(layer "In4.Cu")
		(net "M_C_CPU0_SA_CA<4>")
	)
	(arc
		(start 335.44256 -255.223264)
		(mid 335.255362 -255.173121)
		(end 335.068164 -255.223264)
		(width 0.088646)
		(layer "In4.Cu")
		(net "M_C_CPU0_SA_CA<4>")
	)
	(arc
		(start 339.202014 -255.223264)
		(mid 339.014816 -255.173121)
		(end 338.827618 -255.223264)
		(width 0.088646)
		(layer "In4.Cu")
		(net "M_C_CPU0_SA_CA<4>")
	)
	(arc
		(start 339.75675 -255.22936)
		(mid 339.478572 -255.299052)
		(end 339.202014 -255.223264)
		(width 0.088646)
		(layer "In4.Cu")
		(net "M_C_CPU0_SA_CA<4>")
	)
	(arc
		(start 338.827618 -255.223264)
		(mid 338.550805 -255.2991)
		(end 338.272374 -255.22936)
		(width 0.088646)
		(layer "In4.Cu")
		(net "M_C_CPU0_SA_CA<4>")
	)
	(arc
		(start 334.50276 -255.223264)
		(mid 334.315562 -255.173121)
		(end 334.128364 -255.223264)
		(width 0.088646)
		(layer "In4.Cu")
		(net "M_C_CPU0_SA_CA<4>")
	)
	(arc
		(start 336.948018 -255.223264)
		(mid 336.671205 -255.2991)
		(end 336.392774 -255.22936)
		(width 0.088646)
		(layer "In4.Cu")
		(net "M_C_CPU0_SA_CA<4>")
	)
	(segment
		(start 280.606246 -263.7409)
		(end 280.606246 -263.892538)
		(width 0.20066)
		(layer "F.Cu")
		(net "M_C_CPU0_SA_CA<3>")
	)
	(segment
		(start 341.833962 -256.639314)
		(end 341.833962 -257.175)
		(width 0.20066)
		(layer "F.Cu")
		(net "M_C_CPU0_SA_CA<3>")
	)
	(segment
		(start 280.457148 -264.041636)
		(end 279.912826 -264.041636)
		(width 0.20066)
		(layer "F.Cu")
		(net "M_C_CPU0_SA_CA<3>")
	)
	(segment
		(start 277.233888 -264.05586)
		(end 277.091394 -263.913366)
		(width 0.20066)
		(layer "F.Cu")
		(net "M_C_CPU0_SA_CA<3>")
	)
	(segment
		(start 281.788362 -263.824212)
		(end 281.34183 -263.824212)
		(width 0.20066)
		(layer "F.Cu")
		(net "M_C_CPU0_SA_CA<3>")
	)
	(segment
		(start 279.912826 -264.041636)
		(end 277.839932 -264.041636)
		(width 0.1016)
		(layer "F.Cu")
		(net "M_C_CPU0_SA_CA<3>")
	)
	(segment
		(start 283.916882 -263.616694)
		(end 282.811982 -263.616694)
		(width 0.20066)
		(layer "F.Cu")
		(net "M_C_CPU0_SA_CA<3>")
	)
	(segment
		(start 341.833962 -257.175)
		(end 341.834216 -257.175254)
		(width 0.20066)
		(layer "F.Cu")
		(net "M_C_CPU0_SA_CA<3>")
	)
	(segment
		(start 281.129994 -263.612376)
		(end 280.73477 -263.612376)
		(width 0.20066)
		(layer "F.Cu")
		(net "M_C_CPU0_SA_CA<3>")
	)
	(segment
		(start 280.606246 -263.892538)
		(end 280.457148 -264.041636)
		(width 0.20066)
		(layer "F.Cu")
		(net "M_C_CPU0_SA_CA<3>")
	)
	(segment
		(start 277.091394 -263.913366)
		(end 277.091394 -263.742678)
		(width 0.20066)
		(layer "F.Cu")
		(net "M_C_CPU0_SA_CA<3>")
	)
	(segment
		(start 281.34183 -263.824212)
		(end 281.129994 -263.612376)
		(width 0.20066)
		(layer "F.Cu")
		(net "M_C_CPU0_SA_CA<3>")
	)
	(segment
		(start 276.96541 -263.616694)
		(end 275.268182 -263.616694)
		(width 0.20066)
		(layer "F.Cu")
		(net "M_C_CPU0_SA_CA<3>")
	)
	(segment
		(start 277.601934 -264.041636)
		(end 277.58771 -264.05586)
		(width 0.101854)
		(layer "F.Cu")
		(net "M_C_CPU0_SA_CA<3>")
	)
	(segment
		(start 277.091394 -263.742678)
		(end 276.96541 -263.616694)
		(width 0.20066)
		(layer "F.Cu")
		(net "M_C_CPU0_SA_CA<3>")
	)
	(segment
		(start 277.58771 -264.05586)
		(end 277.233888 -264.05586)
		(width 0.20066)
		(layer "F.Cu")
		(net "M_C_CPU0_SA_CA<3>")
	)
	(segment
		(start 282.811982 -263.616694)
		(end 281.99588 -263.616694)
		(width 0.20066)
		(layer "F.Cu")
		(net "M_C_CPU0_SA_CA<3>")
	)
	(segment
		(start 277.839932 -264.041636)
		(end 277.601934 -264.041636)
		(width 0.101854)
		(layer "F.Cu")
		(net "M_C_CPU0_SA_CA<3>")
	)
	(segment
		(start 281.99588 -263.616694)
		(end 281.788362 -263.824212)
		(width 0.20066)
		(layer "F.Cu")
		(net "M_C_CPU0_SA_CA<3>")
	)
	(segment
		(start 280.73477 -263.612376)
		(end 280.606246 -263.7409)
		(width 0.20066)
		(layer "F.Cu")
		(net "M_C_CPU0_SA_CA<3>")
	)
	(segment
		(start 333.188564 -255.87198)
		(end 333.18831 -255.871726)
		(width 0.088646)
		(layer "In4.Cu")
		(net "M_C_CPU0_SA_CA<3>")
	)
	(segment
		(start 298.003214 -262.341868)
		(end 298.00296 -262.341614)
		(width 0.18288)
		(layer "In4.Cu")
		(net "M_C_CPU0_SA_CA<3>")
	)
	(segment
		(start 311.729374 -260.050026)
		(end 310.477916 -261.301484)
		(width 0.18288)
		(layer "In4.Cu")
		(net "M_C_CPU0_SA_CA<3>")
	)
	(segment
		(start 303.873154 -260.63575)
		(end 303.431448 -261.077456)
		(width 0.18288)
		(layer "In4.Cu")
		(net "M_C_CPU0_SA_CA<3>")
	)
	(segment
		(start 336.392774 -255.865884)
		(end 336.38236 -255.87198)
		(width 0.088646)
		(layer "In4.Cu")
		(net "M_C_CPU0_SA_CA<3>")
	)
	(segment
		(start 307.251862 -261.611872)
		(end 306.330604 -261.611872)
		(width 0.18288)
		(layer "In4.Cu")
		(net "M_C_CPU0_SA_CA<3>")
	)
	(segment
		(start 287.494726 -262.952738)
		(end 286.895794 -262.952738)
		(width 0.18288)
		(layer "In4.Cu")
		(net "M_C_CPU0_SA_CA<3>")
	)
	(segment
		(start 322.096892 -256.84226)
		(end 314.35294 -260.050026)
		(width 0.18288)
		(layer "In4.Cu")
		(net "M_C_CPU0_SA_CA<3>")
	)
	(segment
		(start 331.230478 -255.04521)
		(end 329.433428 -256.84226)
		(width 0.18288)
		(layer "In4.Cu")
		(net "M_C_CPU0_SA_CA<3>")
	)
	(segment
		(start 337.332828 -255.865884)
		(end 337.322414 -255.87198)
		(width 0.088646)
		(layer "In4.Cu")
		(net "M_C_CPU0_SA_CA<3>")
	)
	(segment
		(start 340.049612 -256.361438)
		(end 340.049612 -256.351532)
		(width 0.088646)
		(layer "In4.Cu")
		(net "M_C_CPU0_SA_CA<3>")
	)
	(segment
		(start 306.112418 -260.777482)
		(end 305.970686 -260.63575)
		(width 0.18288)
		(layer "In4.Cu")
		(net "M_C_CPU0_SA_CA<3>")
	)
	(segment
		(start 303.04486 -262.341868)
		(end 298.003214 -262.341868)
		(width 0.18288)
		(layer "In4.Cu")
		(net "M_C_CPU0_SA_CA<3>")
	)
	(segment
		(start 291.468556 -263.425432)
		(end 287.96742 -263.425432)
		(width 0.18288)
		(layer "In4.Cu")
		(net "M_C_CPU0_SA_CA<3>")
	)
	(segment
		(start 333.001112 -255.547622)
		(end 333.001112 -255.344676)
		(width 0.088646)
		(layer "In4.Cu")
		(net "M_C_CPU0_SA_CA<3>")
	)
	(segment
		(start 306.330604 -261.611872)
		(end 306.112418 -261.393686)
		(width 0.18288)
		(layer "In4.Cu")
		(net "M_C_CPU0_SA_CA<3>")
	)
	(segment
		(start 285.809436 -264.039096)
		(end 284.339284 -264.039096)
		(width 0.18288)
		(layer "In4.Cu")
		(net "M_C_CPU0_SA_CA<3>")
	)
	(segment
		(start 307.56225 -261.301484)
		(end 307.251862 -261.611872)
		(width 0.18288)
		(layer "In4.Cu")
		(net "M_C_CPU0_SA_CA<3>")
	)
	(segment
		(start 314.35294 -260.050026)
		(end 311.729374 -260.050026)
		(width 0.18288)
		(layer "In4.Cu")
		(net "M_C_CPU0_SA_CA<3>")
	)
	(segment
		(start 332.375002 -255.04521)
		(end 331.230478 -255.04521)
		(width 0.18288)
		(layer "In4.Cu")
		(net "M_C_CPU0_SA_CA<3>")
	)
	(segment
		(start 339.212428 -255.865884)
		(end 339.202014 -255.87198)
		(width 0.088646)
		(layer "In4.Cu")
		(net "M_C_CPU0_SA_CA<3>")
	)
	(segment
		(start 333.001112 -255.344676)
		(end 332.701646 -255.04521)
		(width 0.088646)
		(layer "In4.Cu")
		(net "M_C_CPU0_SA_CA<3>")
	)
	(segment
		(start 340.872826 -256.776982)
		(end 340.567264 -256.776982)
		(width 0.088646)
		(layer "In4.Cu")
		(net "M_C_CPU0_SA_CA<3>")
	)
	(segment
		(start 303.431448 -261.077456)
		(end 303.431448 -261.95528)
		(width 0.18288)
		(layer "In4.Cu")
		(net "M_C_CPU0_SA_CA<3>")
	)
	(segment
		(start 338.272374 -255.865884)
		(end 338.26196 -255.87198)
		(width 0.088646)
		(layer "In4.Cu")
		(net "M_C_CPU0_SA_CA<3>")
	)
	(segment
		(start 292.552374 -262.341614)
		(end 291.468556 -263.425432)
		(width 0.18288)
		(layer "In4.Cu")
		(net "M_C_CPU0_SA_CA<3>")
	)
	(segment
		(start 284.339284 -264.039096)
		(end 283.916882 -263.616694)
		(width 0.18288)
		(layer "In4.Cu")
		(net "M_C_CPU0_SA_CA<3>")
	)
	(segment
		(start 329.433428 -256.84226)
		(end 322.096892 -256.84226)
		(width 0.18288)
		(layer "In4.Cu")
		(net "M_C_CPU0_SA_CA<3>")
	)
	(segment
		(start 332.701646 -255.04521)
		(end 332.375002 -255.04521)
		(width 0.088646)
		(layer "In4.Cu")
		(net "M_C_CPU0_SA_CA<3>")
	)
	(segment
		(start 340.24316 -256.689352)
		(end 340.237064 -256.685796)
		(width 0.088646)
		(layer "In4.Cu")
		(net "M_C_CPU0_SA_CA<3>")
	)
	(segment
		(start 306.112418 -261.393686)
		(end 306.112418 -260.777482)
		(width 0.18288)
		(layer "In4.Cu")
		(net "M_C_CPU0_SA_CA<3>")
	)
	(segment
		(start 310.477916 -261.301484)
		(end 307.56225 -261.301484)
		(width 0.18288)
		(layer "In4.Cu")
		(net "M_C_CPU0_SA_CA<3>")
	)
	(segment
		(start 298.00296 -262.341614)
		(end 292.552374 -262.341614)
		(width 0.18288)
		(layer "In4.Cu")
		(net "M_C_CPU0_SA_CA<3>")
	)
	(segment
		(start 287.96742 -263.425432)
		(end 287.494726 -262.952738)
		(width 0.18288)
		(layer "In4.Cu")
		(net "M_C_CPU0_SA_CA<3>")
	)
	(segment
		(start 286.895794 -262.952738)
		(end 285.809436 -264.039096)
		(width 0.18288)
		(layer "In4.Cu")
		(net "M_C_CPU0_SA_CA<3>")
	)
	(segment
		(start 303.431448 -261.95528)
		(end 303.04486 -262.341868)
		(width 0.18288)
		(layer "In4.Cu")
		(net "M_C_CPU0_SA_CA<3>")
	)
	(segment
		(start 340.237064 -256.685796)
		(end 340.228174 -256.680716)
		(width 0.088646)
		(layer "In4.Cu")
		(net "M_C_CPU0_SA_CA<3>")
	)
	(segment
		(start 305.970686 -260.63575)
		(end 303.873154 -260.63575)
		(width 0.18288)
		(layer "In4.Cu")
		(net "M_C_CPU0_SA_CA<3>")
	)
	(arc
		(start 337.887564 -255.87198)
		(mid 337.611005 -255.796237)
		(end 337.332828 -255.865884)
		(width 0.088646)
		(layer "In4.Cu")
		(net "M_C_CPU0_SA_CA<3>")
	)
	(arc
		(start 338.26196 -255.87198)
		(mid 338.074762 -255.922123)
		(end 337.887564 -255.87198)
		(width 0.088646)
		(layer "In4.Cu")
		(net "M_C_CPU0_SA_CA<3>")
	)
	(arc
		(start 336.007964 -255.87198)
		(mid 335.725262 -255.796204)
		(end 335.44256 -255.87198)
		(width 0.088646)
		(layer "In4.Cu")
		(net "M_C_CPU0_SA_CA<3>")
	)
	(arc
		(start 336.948018 -255.87198)
		(mid 336.671205 -255.79611)
		(end 336.392774 -255.865884)
		(width 0.088646)
		(layer "In4.Cu")
		(net "M_C_CPU0_SA_CA<3>")
	)
	(arc
		(start 341.834216 -257.175254)
		(mid 341.393127 -256.880527)
		(end 340.872826 -256.776982)
		(width 0.088646)
		(layer "In4.Cu")
		(net "M_C_CPU0_SA_CA<3>")
	)
	(arc
		(start 334.128364 -255.87198)
		(mid 333.845662 -255.796238)
		(end 333.56296 -255.87198)
		(width 0.088646)
		(layer "In4.Cu")
		(net "M_C_CPU0_SA_CA<3>")
	)
	(arc
		(start 340.567264 -256.776982)
		(mid 340.399389 -256.754695)
		(end 340.24316 -256.689352)
		(width 0.088646)
		(layer "In4.Cu")
		(net "M_C_CPU0_SA_CA<3>")
	)
	(arc
		(start 337.322414 -255.87198)
		(mid 337.135216 -255.922123)
		(end 336.948018 -255.87198)
		(width 0.088646)
		(layer "In4.Cu")
		(net "M_C_CPU0_SA_CA<3>")
	)
	(arc
		(start 333.56296 -255.87198)
		(mid 333.375762 -255.922157)
		(end 333.188564 -255.87198)
		(width 0.088646)
		(layer "In4.Cu")
		(net "M_C_CPU0_SA_CA<3>")
	)
	(arc
		(start 339.767164 -255.87198)
		(mid 339.490605 -255.796237)
		(end 339.212428 -255.865884)
		(width 0.088646)
		(layer "In4.Cu")
		(net "M_C_CPU0_SA_CA<3>")
	)
	(arc
		(start 334.50276 -255.87198)
		(mid 334.315562 -255.922123)
		(end 334.128364 -255.87198)
		(width 0.088646)
		(layer "In4.Cu")
		(net "M_C_CPU0_SA_CA<3>")
	)
	(arc
		(start 336.38236 -255.87198)
		(mid 336.195162 -255.922123)
		(end 336.007964 -255.87198)
		(width 0.088646)
		(layer "In4.Cu")
		(net "M_C_CPU0_SA_CA<3>")
	)
	(arc
		(start 333.18831 -255.871726)
		(mid 333.051265 -255.734766)
		(end 333.001112 -255.547622)
		(width 0.088646)
		(layer "In4.Cu")
		(net "M_C_CPU0_SA_CA<3>")
	)
	(arc
		(start 340.228174 -256.680716)
		(mid 340.09726 -256.544356)
		(end 340.049612 -256.361438)
		(width 0.088646)
		(layer "In4.Cu")
		(net "M_C_CPU0_SA_CA<3>")
	)
	(arc
		(start 335.44256 -255.87198)
		(mid 335.255362 -255.922123)
		(end 335.068164 -255.87198)
		(width 0.088646)
		(layer "In4.Cu")
		(net "M_C_CPU0_SA_CA<3>")
	)
	(arc
		(start 340.049612 -256.351532)
		(mid 339.971501 -256.074583)
		(end 339.767164 -255.87198)
		(width 0.088646)
		(layer "In4.Cu")
		(net "M_C_CPU0_SA_CA<3>")
	)
	(arc
		(start 335.068164 -255.87198)
		(mid 334.785462 -255.796204)
		(end 334.50276 -255.87198)
		(width 0.088646)
		(layer "In4.Cu")
		(net "M_C_CPU0_SA_CA<3>")
	)
	(arc
		(start 339.202014 -255.87198)
		(mid 339.014816 -255.922123)
		(end 338.827618 -255.87198)
		(width 0.088646)
		(layer "In4.Cu")
		(net "M_C_CPU0_SA_CA<3>")
	)
	(arc
		(start 338.827618 -255.87198)
		(mid 338.550805 -255.79611)
		(end 338.272374 -255.865884)
		(width 0.088646)
		(layer "In4.Cu")
		(net "M_C_CPU0_SA_CA<3>")
	)
	(segment
		(start 273.53514 -264.032746)
		(end 273.37258 -264.195306)
		(width 0.20066)
		(layer "F.Cu")
		(net "M_C_CPU0_SA_CA<2>")
	)
	(segment
		(start 272.502376 -264.466578)
		(end 271.168114 -264.466578)
		(width 0.20066)
		(layer "F.Cu")
		(net "M_C_CPU0_SA_CA<2>")
	)
	(segment
		(start 273.218148 -264.677906)
		(end 272.713704 -264.677906)
		(width 0.20066)
		(layer "F.Cu")
		(net "M_C_CPU0_SA_CA<2>")
	)
	(segment
		(start 274.143978 -264.032746)
		(end 273.53514 -264.032746)
		(width 0.20066)
		(layer "F.Cu")
		(net "M_C_CPU0_SA_CA<2>")
	)
	(segment
		(start 273.37258 -264.195306)
		(end 273.37258 -264.523474)
		(width 0.20066)
		(layer "F.Cu")
		(net "M_C_CPU0_SA_CA<2>")
	)
	(segment
		(start 339.954362 -257.175)
		(end 339.954616 -257.175254)
		(width 0.20066)
		(layer "F.Cu")
		(net "M_C_CPU0_SA_CA<2>")
	)
	(segment
		(start 339.954362 -256.639314)
		(end 339.954362 -257.175)
		(width 0.20066)
		(layer "F.Cu")
		(net "M_C_CPU0_SA_CA<2>")
	)
	(segment
		(start 276.469094 -264.041636)
		(end 276.138386 -264.041636)
		(width 0.101854)
		(layer "F.Cu")
		(net "M_C_CPU0_SA_CA<2>")
	)
	(segment
		(start 279.816814 -264.466578)
		(end 278.711914 -264.466578)
		(width 0.20066)
		(layer "F.Cu")
		(net "M_C_CPU0_SA_CA<2>")
	)
	(segment
		(start 276.138386 -264.041636)
		(end 274.152868 -264.041636)
		(width 0.1016)
		(layer "F.Cu")
		(net "M_C_CPU0_SA_CA<2>")
	)
	(segment
		(start 278.711914 -264.466578)
		(end 277.072598 -264.466578)
		(width 0.20066)
		(layer "F.Cu")
		(net "M_C_CPU0_SA_CA<2>")
	)
	(segment
		(start 272.713704 -264.677906)
		(end 272.502376 -264.466578)
		(width 0.20066)
		(layer "F.Cu")
		(net "M_C_CPU0_SA_CA<2>")
	)
	(segment
		(start 274.152868 -264.041636)
		(end 274.143978 -264.032746)
		(width 0.1016)
		(layer "F.Cu")
		(net "M_C_CPU0_SA_CA<2>")
	)
	(segment
		(start 276.647656 -264.041636)
		(end 276.469094 -264.041636)
		(width 0.20066)
		(layer "F.Cu")
		(net "M_C_CPU0_SA_CA<2>")
	)
	(segment
		(start 273.37258 -264.523474)
		(end 273.218148 -264.677906)
		(width 0.20066)
		(layer "F.Cu")
		(net "M_C_CPU0_SA_CA<2>")
	)
	(segment
		(start 277.072598 -264.466578)
		(end 276.647656 -264.041636)
		(width 0.20066)
		(layer "F.Cu")
		(net "M_C_CPU0_SA_CA<2>")
	)
	(segment
		(start 306.933092 -262.156956)
		(end 306.079906 -262.156956)
		(width 0.18288)
		(layer "In4.Cu")
		(net "M_C_CPU0_SA_CA<2>")
	)
	(segment
		(start 332.375002 -255.971548)
		(end 332.224126 -255.971548)
		(width 0.18288)
		(layer "In4.Cu")
		(net "M_C_CPU0_SA_CA<2>")
	)
	(segment
		(start 339.297264 -256.03708)
		(end 339.282532 -256.045716)
		(width 0.088646)
		(layer "In4.Cu")
		(net "M_C_CPU0_SA_CA<2>")
	)
	(segment
		(start 312.623454 -261.66318)
		(end 311.25668 -261.66318)
		(width 0.18288)
		(layer "In4.Cu")
		(net "M_C_CPU0_SA_CA<2>")
	)
	(segment
		(start 307.325776 -262.54964)
		(end 306.933092 -262.156956)
		(width 0.18288)
		(layer "In4.Cu")
		(net "M_C_CPU0_SA_CA<2>")
	)
	(segment
		(start 332.224126 -255.971548)
		(end 331.99832 -255.745742)
		(width 0.18288)
		(layer "In4.Cu")
		(net "M_C_CPU0_SA_CA<2>")
	)
	(segment
		(start 333.375762 -256.112772)
		(end 333.087726 -256.112772)
		(width 0.088646)
		(layer "In4.Cu")
		(net "M_C_CPU0_SA_CA<2>")
	)
	(segment
		(start 332.946502 -255.971548)
		(end 332.375002 -255.971548)
		(width 0.088646)
		(layer "In4.Cu")
		(net "M_C_CPU0_SA_CA<2>")
	)
	(segment
		(start 287.00349 -264.041636)
		(end 286.15132 -264.893806)
		(width 0.18288)
		(layer "In4.Cu")
		(net "M_C_CPU0_SA_CA<2>")
	)
	(segment
		(start 292.441376 -263.191752)
		(end 291.591492 -264.041636)
		(width 0.18288)
		(layer "In4.Cu")
		(net "M_C_CPU0_SA_CA<2>")
	)
	(segment
		(start 314.34151 -260.61924)
		(end 313.92368 -260.61924)
		(width 0.18288)
		(layer "In4.Cu")
		(net "M_C_CPU0_SA_CA<2>")
	)
	(segment
		(start 331.234034 -255.745742)
		(end 329.802236 -257.17754)
		(width 0.18288)
		(layer "In4.Cu")
		(net "M_C_CPU0_SA_CA<2>")
	)
	(segment
		(start 280.244042 -264.893806)
		(end 279.816814 -264.466578)
		(width 0.18288)
		(layer "In4.Cu")
		(net "M_C_CPU0_SA_CA<2>")
	)
	(segment
		(start 339.68055 -256.04216)
		(end 339.67166 -256.03708)
		(width 0.088646)
		(layer "In4.Cu")
		(net "M_C_CPU0_SA_CA<2>")
	)
	(segment
		(start 303.185576 -263.191752)
		(end 292.441376 -263.191752)
		(width 0.18288)
		(layer "In4.Cu")
		(net "M_C_CPU0_SA_CA<2>")
	)
	(segment
		(start 331.99832 -255.745742)
		(end 331.234034 -255.745742)
		(width 0.18288)
		(layer "In4.Cu")
		(net "M_C_CPU0_SA_CA<2>")
	)
	(segment
		(start 306.079906 -262.156956)
		(end 305.731164 -261.808214)
		(width 0.18288)
		(layer "In4.Cu")
		(net "M_C_CPU0_SA_CA<2>")
	)
	(segment
		(start 310.37022 -262.54964)
		(end 307.325776 -262.54964)
		(width 0.18288)
		(layer "In4.Cu")
		(net "M_C_CPU0_SA_CA<2>")
	)
	(segment
		(start 322.650612 -257.17754)
		(end 314.34151 -260.61924)
		(width 0.18288)
		(layer "In4.Cu")
		(net "M_C_CPU0_SA_CA<2>")
	)
	(segment
		(start 339.859112 -257.07975)
		(end 339.859112 -256.361438)
		(width 0.088646)
		(layer "In4.Cu")
		(net "M_C_CPU0_SA_CA<2>")
	)
	(segment
		(start 305.731164 -261.808214)
		(end 304.569114 -261.808214)
		(width 0.18288)
		(layer "In4.Cu")
		(net "M_C_CPU0_SA_CA<2>")
	)
	(segment
		(start 339.954616 -257.175254)
		(end 339.859112 -257.07975)
		(width 0.088646)
		(layer "In4.Cu")
		(net "M_C_CPU0_SA_CA<2>")
	)
	(segment
		(start 304.569114 -261.808214)
		(end 303.185576 -263.191752)
		(width 0.18288)
		(layer "In4.Cu")
		(net "M_C_CPU0_SA_CA<2>")
	)
	(segment
		(start 313.486038 -260.800596)
		(end 312.623454 -261.66318)
		(width 0.18288)
		(layer "In4.Cu")
		(net "M_C_CPU0_SA_CA<2>")
	)
	(segment
		(start 313.92368 -260.61924)
		(end 313.486038 -260.800596)
		(width 0.18288)
		(layer "In4.Cu")
		(net "M_C_CPU0_SA_CA<2>")
	)
	(segment
		(start 311.25668 -261.66318)
		(end 310.37022 -262.54964)
		(width 0.18288)
		(layer "In4.Cu")
		(net "M_C_CPU0_SA_CA<2>")
	)
	(segment
		(start 329.802236 -257.17754)
		(end 322.650612 -257.17754)
		(width 0.18288)
		(layer "In4.Cu")
		(net "M_C_CPU0_SA_CA<2>")
	)
	(segment
		(start 291.591492 -264.041636)
		(end 287.00349 -264.041636)
		(width 0.18288)
		(layer "In4.Cu")
		(net "M_C_CPU0_SA_CA<2>")
	)
	(segment
		(start 286.15132 -264.893806)
		(end 280.244042 -264.893806)
		(width 0.18288)
		(layer "In4.Cu")
		(net "M_C_CPU0_SA_CA<2>")
	)
	(segment
		(start 333.087726 -256.112772)
		(end 332.946502 -255.971548)
		(width 0.088646)
		(layer "In4.Cu")
		(net "M_C_CPU0_SA_CA<2>")
	)
	(segment
		(start 337.417664 -256.03708)
		(end 337.402932 -256.045716)
		(width 0.088646)
		(layer "In4.Cu")
		(net "M_C_CPU0_SA_CA<2>")
	)
	(arc
		(start 339.859112 -256.361438)
		(mid 339.811433 -256.178538)
		(end 339.68055 -256.04216)
		(width 0.088646)
		(layer "In4.Cu")
		(net "M_C_CPU0_SA_CA<2>")
	)
	(arc
		(start 334.598264 -256.03708)
		(mid 334.315562 -256.112856)
		(end 334.03286 -256.03708)
		(width 0.088646)
		(layer "In4.Cu")
		(net "M_C_CPU0_SA_CA<2>")
	)
	(arc
		(start 335.538064 -256.03708)
		(mid 335.255362 -256.112856)
		(end 334.97266 -256.03708)
		(width 0.088646)
		(layer "In4.Cu")
		(net "M_C_CPU0_SA_CA<2>")
	)
	(arc
		(start 338.357464 -256.03708)
		(mid 338.074762 -256.112856)
		(end 337.79206 -256.03708)
		(width 0.088646)
		(layer "In4.Cu")
		(net "M_C_CPU0_SA_CA<2>")
	)
	(arc
		(start 334.97266 -256.03708)
		(mid 334.785462 -255.986937)
		(end 334.598264 -256.03708)
		(width 0.088646)
		(layer "In4.Cu")
		(net "M_C_CPU0_SA_CA<2>")
	)
	(arc
		(start 339.282532 -256.045716)
		(mid 339.006057 -256.113036)
		(end 338.73186 -256.03708)
		(width 0.088646)
		(layer "In4.Cu")
		(net "M_C_CPU0_SA_CA<2>")
	)
	(arc
		(start 337.79206 -256.03708)
		(mid 337.604862 -255.986937)
		(end 337.417664 -256.03708)
		(width 0.088646)
		(layer "In4.Cu")
		(net "M_C_CPU0_SA_CA<2>")
	)
	(arc
		(start 335.91246 -256.03708)
		(mid 335.725262 -255.986937)
		(end 335.538064 -256.03708)
		(width 0.088646)
		(layer "In4.Cu")
		(net "M_C_CPU0_SA_CA<2>")
	)
	(arc
		(start 336.85226 -256.03708)
		(mid 336.665062 -255.986937)
		(end 336.477864 -256.03708)
		(width 0.088646)
		(layer "In4.Cu")
		(net "M_C_CPU0_SA_CA<2>")
	)
	(arc
		(start 334.03286 -256.03708)
		(mid 333.845662 -255.986937)
		(end 333.658464 -256.03708)
		(width 0.088646)
		(layer "In4.Cu")
		(net "M_C_CPU0_SA_CA<2>")
	)
	(arc
		(start 336.477864 -256.03708)
		(mid 336.195162 -256.112856)
		(end 335.91246 -256.03708)
		(width 0.088646)
		(layer "In4.Cu")
		(net "M_C_CPU0_SA_CA<2>")
	)
	(arc
		(start 333.658464 -256.03708)
		(mid 333.522095 -256.093522)
		(end 333.375762 -256.112772)
		(width 0.088646)
		(layer "In4.Cu")
		(net "M_C_CPU0_SA_CA<2>")
	)
	(arc
		(start 337.402932 -256.045716)
		(mid 337.126457 -256.113036)
		(end 336.85226 -256.03708)
		(width 0.088646)
		(layer "In4.Cu")
		(net "M_C_CPU0_SA_CA<2>")
	)
	(arc
		(start 338.73186 -256.03708)
		(mid 338.544662 -255.986937)
		(end 338.357464 -256.03708)
		(width 0.088646)
		(layer "In4.Cu")
		(net "M_C_CPU0_SA_CA<2>")
	)
	(arc
		(start 339.67166 -256.03708)
		(mid 339.484462 -255.986937)
		(end 339.297264 -256.03708)
		(width 0.088646)
		(layer "In4.Cu")
		(net "M_C_CPU0_SA_CA<2>")
	)
	(segment
		(start 279.912826 -265.741658)
		(end 277.839932 -265.741658)
		(width 0.1016)
		(layer "F.Cu")
		(net "M_C_CPU0_SA_CA<1>")
	)
	(segment
		(start 276.96541 -265.316716)
		(end 275.268182 -265.316716)
		(width 0.20066)
		(layer "F.Cu")
		(net "M_C_CPU0_SA_CA<1>")
	)
	(segment
		(start 280.457148 -265.741658)
		(end 279.912826 -265.741658)
		(width 0.20066)
		(layer "F.Cu")
		(net "M_C_CPU0_SA_CA<1>")
	)
	(segment
		(start 277.233888 -265.755882)
		(end 277.091394 -265.613388)
		(width 0.20066)
		(layer "F.Cu")
		(net "M_C_CPU0_SA_CA<1>")
	)
	(segment
		(start 277.601934 -265.741658)
		(end 277.58771 -265.755882)
		(width 0.101854)
		(layer "F.Cu")
		(net "M_C_CPU0_SA_CA<1>")
	)
	(segment
		(start 281.788362 -265.524234)
		(end 281.34183 -265.524234)
		(width 0.20066)
		(layer "F.Cu")
		(net "M_C_CPU0_SA_CA<1>")
	)
	(segment
		(start 342.304116 -257.45313)
		(end 342.304116 -257.988816)
		(width 0.20066)
		(layer "F.Cu")
		(net "M_C_CPU0_SA_CA<1>")
	)
	(segment
		(start 281.34183 -265.524234)
		(end 281.129994 -265.312398)
		(width 0.20066)
		(layer "F.Cu")
		(net "M_C_CPU0_SA_CA<1>")
	)
	(segment
		(start 280.606246 -265.440922)
		(end 280.606246 -265.59256)
		(width 0.20066)
		(layer "F.Cu")
		(net "M_C_CPU0_SA_CA<1>")
	)
	(segment
		(start 277.839932 -265.741658)
		(end 277.601934 -265.741658)
		(width 0.101854)
		(layer "F.Cu")
		(net "M_C_CPU0_SA_CA<1>")
	)
	(segment
		(start 277.58771 -265.755882)
		(end 277.233888 -265.755882)
		(width 0.20066)
		(layer "F.Cu")
		(net "M_C_CPU0_SA_CA<1>")
	)
	(segment
		(start 277.091394 -265.613388)
		(end 277.091394 -265.4427)
		(width 0.20066)
		(layer "F.Cu")
		(net "M_C_CPU0_SA_CA<1>")
	)
	(segment
		(start 283.916882 -265.316716)
		(end 282.811982 -265.316716)
		(width 0.20066)
		(layer "F.Cu")
		(net "M_C_CPU0_SA_CA<1>")
	)
	(segment
		(start 280.606246 -265.59256)
		(end 280.457148 -265.741658)
		(width 0.20066)
		(layer "F.Cu")
		(net "M_C_CPU0_SA_CA<1>")
	)
	(segment
		(start 277.091394 -265.4427)
		(end 276.96541 -265.316716)
		(width 0.20066)
		(layer "F.Cu")
		(net "M_C_CPU0_SA_CA<1>")
	)
	(segment
		(start 282.811982 -265.316716)
		(end 281.99588 -265.316716)
		(width 0.20066)
		(layer "F.Cu")
		(net "M_C_CPU0_SA_CA<1>")
	)
	(segment
		(start 281.129994 -265.312398)
		(end 280.73477 -265.312398)
		(width 0.20066)
		(layer "F.Cu")
		(net "M_C_CPU0_SA_CA<1>")
	)
	(segment
		(start 280.73477 -265.312398)
		(end 280.606246 -265.440922)
		(width 0.20066)
		(layer "F.Cu")
		(net "M_C_CPU0_SA_CA<1>")
	)
	(segment
		(start 342.304116 -257.988816)
		(end 342.303862 -257.98907)
		(width 0.20066)
		(layer "F.Cu")
		(net "M_C_CPU0_SA_CA<1>")
	)
	(segment
		(start 281.99588 -265.316716)
		(end 281.788362 -265.524234)
		(width 0.20066)
		(layer "F.Cu")
		(net "M_C_CPU0_SA_CA<1>")
	)
	(segment
		(start 305.816762 -263.410446)
		(end 305.633882 -263.227566)
		(width 0.18288)
		(layer "In4.Cu")
		(net "M_C_CPU0_SA_CA<1>")
	)
	(segment
		(start 303.863248 -263.410446)
		(end 303.232058 -264.041636)
		(width 0.18288)
		(layer "In4.Cu")
		(net "M_C_CPU0_SA_CA<1>")
	)
	(segment
		(start 312.84164 -262.186928)
		(end 311.71261 -262.186928)
		(width 0.18288)
		(layer "In4.Cu")
		(net "M_C_CPU0_SA_CA<1>")
	)
	(segment
		(start 284.353254 -265.753088)
		(end 283.916882 -265.316716)
		(width 0.18288)
		(layer "In4.Cu")
		(net "M_C_CPU0_SA_CA<1>")
	)
	(segment
		(start 304.760122 -263.410446)
		(end 303.863248 -263.410446)
		(width 0.18288)
		(layer "In4.Cu")
		(net "M_C_CPU0_SA_CA<1>")
	)
	(segment
		(start 331.214476 -256.469642)
		(end 330.171298 -257.51282)
		(width 0.18288)
		(layer "In4.Cu")
		(net "M_C_CPU0_SA_CA<1>")
	)
	(segment
		(start 342.303862 -257.98907)
		(end 341.62492 -257.585972)
		(width 0.088646)
		(layer "In4.Cu")
		(net "M_C_CPU0_SA_CA<1>")
	)
	(segment
		(start 333.003906 -256.610104)
		(end 332.863444 -256.469642)
		(width 0.088646)
		(layer "In4.Cu")
		(net "M_C_CPU0_SA_CA<1>")
	)
	(segment
		(start 307.006244 -263.410446)
		(end 305.816762 -263.410446)
		(width 0.18288)
		(layer "In4.Cu")
		(net "M_C_CPU0_SA_CA<1>")
	)
	(segment
		(start 305.125882 -262.593582)
		(end 304.943002 -262.776462)
		(width 0.18288)
		(layer "In4.Cu")
		(net "M_C_CPU0_SA_CA<1>")
	)
	(segment
		(start 333.375762 -256.610104)
		(end 333.003906 -256.610104)
		(width 0.088646)
		(layer "In4.Cu")
		(net "M_C_CPU0_SA_CA<1>")
	)
	(segment
		(start 339.309456 -256.692908)
		(end 339.297264 -256.685796)
		(width 0.088646)
		(layer "In4.Cu")
		(net "M_C_CPU0_SA_CA<1>")
	)
	(segment
		(start 304.943002 -262.776462)
		(end 304.943002 -263.227566)
		(width 0.18288)
		(layer "In4.Cu")
		(net "M_C_CPU0_SA_CA<1>")
	)
	(segment
		(start 287.937448 -265.102848)
		(end 287.715706 -264.881106)
		(width 0.18288)
		(layer "In4.Cu")
		(net "M_C_CPU0_SA_CA<1>")
	)
	(segment
		(start 314.24118 -261.6073)
		(end 312.84164 -262.186928)
		(width 0.18288)
		(layer "In4.Cu")
		(net "M_C_CPU0_SA_CA<1>")
	)
	(segment
		(start 332.863444 -256.469642)
		(end 332.375002 -256.469642)
		(width 0.088646)
		(layer "In4.Cu")
		(net "M_C_CPU0_SA_CA<1>")
	)
	(segment
		(start 310.835294 -263.064244)
		(end 309.24373 -263.064244)
		(width 0.18288)
		(layer "In4.Cu")
		(net "M_C_CPU0_SA_CA<1>")
	)
	(segment
		(start 308.36997 -263.315958)
		(end 308.36997 -263.247124)
		(width 0.18288)
		(layer "In4.Cu")
		(net "M_C_CPU0_SA_CA<1>")
	)
	(segment
		(start 291.54628 -265.102848)
		(end 287.937448 -265.102848)
		(width 0.18288)
		(layer "In4.Cu")
		(net "M_C_CPU0_SA_CA<1>")
	)
	(segment
		(start 287.715706 -264.881106)
		(end 287.191958 -264.881106)
		(width 0.18288)
		(layer "In4.Cu")
		(net "M_C_CPU0_SA_CA<1>")
	)
	(segment
		(start 308.55285 -263.498838)
		(end 308.36997 -263.315958)
		(width 0.18288)
		(layer "In4.Cu")
		(net "M_C_CPU0_SA_CA<1>")
	)
	(segment
		(start 323.178424 -257.51282)
		(end 314.910978 -260.937502)
		(width 0.18288)
		(layer "In4.Cu")
		(net "M_C_CPU0_SA_CA<1>")
	)
	(segment
		(start 311.71261 -262.186928)
		(end 310.835294 -263.064244)
		(width 0.18288)
		(layer "In4.Cu")
		(net "M_C_CPU0_SA_CA<1>")
	)
	(segment
		(start 308.87797 -263.498838)
		(end 308.55285 -263.498838)
		(width 0.18288)
		(layer "In4.Cu")
		(net "M_C_CPU0_SA_CA<1>")
	)
	(segment
		(start 305.633882 -263.227566)
		(end 305.633882 -262.776462)
		(width 0.18288)
		(layer "In4.Cu")
		(net "M_C_CPU0_SA_CA<1>")
	)
	(segment
		(start 309.06085 -263.247124)
		(end 309.06085 -263.315958)
		(width 0.18288)
		(layer "In4.Cu")
		(net "M_C_CPU0_SA_CA<1>")
	)
	(segment
		(start 286.319976 -265.753088)
		(end 284.353254 -265.753088)
		(width 0.18288)
		(layer "In4.Cu")
		(net "M_C_CPU0_SA_CA<1>")
	)
	(segment
		(start 307.352446 -263.064244)
		(end 307.006244 -263.410446)
		(width 0.18288)
		(layer "In4.Cu")
		(net "M_C_CPU0_SA_CA<1>")
	)
	(segment
		(start 341.62492 -257.585972)
		(end 339.918548 -257.585972)
		(width 0.088646)
		(layer "In4.Cu")
		(net "M_C_CPU0_SA_CA<1>")
	)
	(segment
		(start 304.943002 -263.227566)
		(end 304.760122 -263.410446)
		(width 0.18288)
		(layer "In4.Cu")
		(net "M_C_CPU0_SA_CA<1>")
	)
	(segment
		(start 287.191958 -264.881106)
		(end 286.319976 -265.753088)
		(width 0.18288)
		(layer "In4.Cu")
		(net "M_C_CPU0_SA_CA<1>")
	)
	(segment
		(start 292.607492 -264.041636)
		(end 291.54628 -265.102848)
		(width 0.18288)
		(layer "In4.Cu")
		(net "M_C_CPU0_SA_CA<1>")
	)
	(segment
		(start 339.918548 -257.585972)
		(end 339.758528 -257.494532)
		(width 0.088646)
		(layer "In4.Cu")
		(net "M_C_CPU0_SA_CA<1>")
	)
	(segment
		(start 308.18709 -263.064244)
		(end 307.352446 -263.064244)
		(width 0.18288)
		(layer "In4.Cu")
		(net "M_C_CPU0_SA_CA<1>")
	)
	(segment
		(start 305.633882 -262.776462)
		(end 305.451002 -262.593582)
		(width 0.18288)
		(layer "In4.Cu")
		(net "M_C_CPU0_SA_CA<1>")
	)
	(segment
		(start 330.171298 -257.51282)
		(end 323.178424 -257.51282)
		(width 0.18288)
		(layer "In4.Cu")
		(net "M_C_CPU0_SA_CA<1>")
	)
	(segment
		(start 314.910978 -260.937502)
		(end 314.24118 -261.6073)
		(width 0.18288)
		(layer "In4.Cu")
		(net "M_C_CPU0_SA_CA<1>")
	)
	(segment
		(start 332.375002 -256.469642)
		(end 331.214476 -256.469642)
		(width 0.18288)
		(layer "In4.Cu")
		(net "M_C_CPU0_SA_CA<1>")
	)
	(segment
		(start 308.36997 -263.247124)
		(end 308.18709 -263.064244)
		(width 0.18288)
		(layer "In4.Cu")
		(net "M_C_CPU0_SA_CA<1>")
	)
	(segment
		(start 303.232058 -264.041636)
		(end 292.607492 -264.041636)
		(width 0.18288)
		(layer "In4.Cu")
		(net "M_C_CPU0_SA_CA<1>")
	)
	(segment
		(start 309.06085 -263.315958)
		(end 308.87797 -263.498838)
		(width 0.18288)
		(layer "In4.Cu")
		(net "M_C_CPU0_SA_CA<1>")
	)
	(segment
		(start 309.24373 -263.064244)
		(end 309.06085 -263.247124)
		(width 0.18288)
		(layer "In4.Cu")
		(net "M_C_CPU0_SA_CA<1>")
	)
	(segment
		(start 305.451002 -262.593582)
		(end 305.125882 -262.593582)
		(width 0.18288)
		(layer "In4.Cu")
		(net "M_C_CPU0_SA_CA<1>")
	)
	(arc
		(start 337.417664 -256.685796)
		(mid 337.134962 -256.61002)
		(end 336.85226 -256.685796)
		(width 0.088646)
		(layer "In4.Cu")
		(net "M_C_CPU0_SA_CA<1>")
	)
	(arc
		(start 333.658464 -256.685796)
		(mid 333.522095 -256.629354)
		(end 333.375762 -256.610104)
		(width 0.088646)
		(layer "In4.Cu")
		(net "M_C_CPU0_SA_CA<1>")
	)
	(arc
		(start 339.758528 -257.494532)
		(mid 339.627614 -257.358172)
		(end 339.579966 -257.175254)
		(width 0.088646)
		(layer "In4.Cu")
		(net "M_C_CPU0_SA_CA<1>")
	)
	(arc
		(start 336.477864 -256.685796)
		(mid 336.195162 -256.61002)
		(end 335.91246 -256.685796)
		(width 0.088646)
		(layer "In4.Cu")
		(net "M_C_CPU0_SA_CA<1>")
	)
	(arc
		(start 335.91246 -256.685796)
		(mid 335.725262 -256.735939)
		(end 335.538064 -256.685796)
		(width 0.088646)
		(layer "In4.Cu")
		(net "M_C_CPU0_SA_CA<1>")
	)
	(arc
		(start 337.79206 -256.685796)
		(mid 337.604862 -256.735939)
		(end 337.417664 -256.685796)
		(width 0.088646)
		(layer "In4.Cu")
		(net "M_C_CPU0_SA_CA<1>")
	)
	(arc
		(start 334.97266 -256.685796)
		(mid 334.785462 -256.735939)
		(end 334.598264 -256.685796)
		(width 0.088646)
		(layer "In4.Cu")
		(net "M_C_CPU0_SA_CA<1>")
	)
	(arc
		(start 334.03286 -256.685796)
		(mid 333.845662 -256.735939)
		(end 333.658464 -256.685796)
		(width 0.088646)
		(layer "In4.Cu")
		(net "M_C_CPU0_SA_CA<1>")
	)
	(arc
		(start 336.85226 -256.685796)
		(mid 336.665062 -256.735939)
		(end 336.477864 -256.685796)
		(width 0.088646)
		(layer "In4.Cu")
		(net "M_C_CPU0_SA_CA<1>")
	)
	(arc
		(start 338.357464 -256.685796)
		(mid 338.074762 -256.61002)
		(end 337.79206 -256.685796)
		(width 0.088646)
		(layer "In4.Cu")
		(net "M_C_CPU0_SA_CA<1>")
	)
	(arc
		(start 339.297264 -256.685796)
		(mid 339.014562 -256.61002)
		(end 338.73186 -256.685796)
		(width 0.088646)
		(layer "In4.Cu")
		(net "M_C_CPU0_SA_CA<1>")
	)
	(arc
		(start 339.579966 -257.175254)
		(mid 339.507731 -256.89873)
		(end 339.309456 -256.692908)
		(width 0.088646)
		(layer "In4.Cu")
		(net "M_C_CPU0_SA_CA<1>")
	)
	(arc
		(start 338.73186 -256.685796)
		(mid 338.544662 -256.735939)
		(end 338.357464 -256.685796)
		(width 0.088646)
		(layer "In4.Cu")
		(net "M_C_CPU0_SA_CA<1>")
	)
	(arc
		(start 335.538064 -256.685796)
		(mid 335.255362 -256.61002)
		(end 334.97266 -256.685796)
		(width 0.088646)
		(layer "In4.Cu")
		(net "M_C_CPU0_SA_CA<1>")
	)
	(arc
		(start 334.598264 -256.685796)
		(mid 334.315562 -256.61002)
		(end 334.03286 -256.685796)
		(width 0.088646)
		(layer "In4.Cu")
		(net "M_C_CPU0_SA_CA<1>")
	)
	(segment
		(start 339.484716 -257.988816)
		(end 339.484462 -257.98907)
		(width 0.20066)
		(layer "F.Cu")
		(net "M_C_CPU0_SA_CA<0>")
	)
	(segment
		(start 276.647656 -265.741658)
		(end 276.469094 -265.741658)
		(width 0.20066)
		(layer "F.Cu")
		(net "M_C_CPU0_SA_CA<0>")
	)
	(segment
		(start 273.53514 -265.732768)
		(end 273.37258 -265.895328)
		(width 0.20066)
		(layer "F.Cu")
		(net "M_C_CPU0_SA_CA<0>")
	)
	(segment
		(start 272.713704 -266.377928)
		(end 272.502376 -266.1666)
		(width 0.20066)
		(layer "F.Cu")
		(net "M_C_CPU0_SA_CA<0>")
	)
	(segment
		(start 273.37258 -266.223496)
		(end 273.218148 -266.377928)
		(width 0.20066)
		(layer "F.Cu")
		(net "M_C_CPU0_SA_CA<0>")
	)
	(segment
		(start 272.502376 -266.1666)
		(end 271.168114 -266.1666)
		(width 0.20066)
		(layer "F.Cu")
		(net "M_C_CPU0_SA_CA<0>")
	)
	(segment
		(start 278.711914 -266.1666)
		(end 277.072598 -266.1666)
		(width 0.20066)
		(layer "F.Cu")
		(net "M_C_CPU0_SA_CA<0>")
	)
	(segment
		(start 276.138386 -265.741658)
		(end 274.152868 -265.741658)
		(width 0.1016)
		(layer "F.Cu")
		(net "M_C_CPU0_SA_CA<0>")
	)
	(segment
		(start 273.218148 -266.377928)
		(end 272.713704 -266.377928)
		(width 0.20066)
		(layer "F.Cu")
		(net "M_C_CPU0_SA_CA<0>")
	)
	(segment
		(start 277.072598 -266.1666)
		(end 276.647656 -265.741658)
		(width 0.20066)
		(layer "F.Cu")
		(net "M_C_CPU0_SA_CA<0>")
	)
	(segment
		(start 279.816814 -266.1666)
		(end 278.711914 -266.1666)
		(width 0.20066)
		(layer "F.Cu")
		(net "M_C_CPU0_SA_CA<0>")
	)
	(segment
		(start 339.484716 -257.45313)
		(end 339.484716 -257.988816)
		(width 0.20066)
		(layer "F.Cu")
		(net "M_C_CPU0_SA_CA<0>")
	)
	(segment
		(start 273.37258 -265.895328)
		(end 273.37258 -266.223496)
		(width 0.20066)
		(layer "F.Cu")
		(net "M_C_CPU0_SA_CA<0>")
	)
	(segment
		(start 276.469094 -265.741658)
		(end 276.138386 -265.741658)
		(width 0.101854)
		(layer "F.Cu")
		(net "M_C_CPU0_SA_CA<0>")
	)
	(segment
		(start 274.143978 -265.732768)
		(end 273.53514 -265.732768)
		(width 0.20066)
		(layer "F.Cu")
		(net "M_C_CPU0_SA_CA<0>")
	)
	(segment
		(start 274.152868 -265.741658)
		(end 274.143978 -265.732768)
		(width 0.1016)
		(layer "F.Cu")
		(net "M_C_CPU0_SA_CA<0>")
	)
	(segment
		(start 333.375762 -256.80035)
		(end 333.046578 -256.80035)
		(width 0.088646)
		(layer "In4.Cu")
		(net "M_C_CPU0_SA_CA<0>")
	)
	(segment
		(start 307.34381 -263.933686)
		(end 304.066448 -263.933686)
		(width 0.18288)
		(layer "In4.Cu")
		(net "M_C_CPU0_SA_CA<0>")
	)
	(segment
		(start 280.241756 -265.741658)
		(end 279.816814 -266.1666)
		(width 0.18288)
		(layer "In4.Cu")
		(net "M_C_CPU0_SA_CA<0>")
	)
	(segment
		(start 304.066448 -263.933686)
		(end 303.10836 -264.891774)
		(width 0.18288)
		(layer "In4.Cu")
		(net "M_C_CPU0_SA_CA<0>")
	)
	(segment
		(start 287.982914 -265.669776)
		(end 287.062164 -266.590526)
		(width 0.18288)
		(layer "In4.Cu")
		(net "M_C_CPU0_SA_CA<0>")
	)
	(segment
		(start 312.263028 -263.330944)
		(end 311.484264 -263.330944)
		(width 0.18288)
		(layer "In4.Cu")
		(net "M_C_CPU0_SA_CA<0>")
	)
	(segment
		(start 323.684646 -257.8481)
		(end 315.243464 -261.344664)
		(width 0.18288)
		(layer "In4.Cu")
		(net "M_C_CPU0_SA_CA<0>")
	)
	(segment
		(start 291.715952 -265.669776)
		(end 287.982914 -265.669776)
		(width 0.18288)
		(layer "In4.Cu")
		(net "M_C_CPU0_SA_CA<0>")
	)
	(segment
		(start 292.493954 -264.891774)
		(end 291.715952 -265.669776)
		(width 0.18288)
		(layer "In4.Cu")
		(net "M_C_CPU0_SA_CA<0>")
	)
	(segment
		(start 303.10836 -264.891774)
		(end 292.493954 -264.891774)
		(width 0.18288)
		(layer "In4.Cu")
		(net "M_C_CPU0_SA_CA<0>")
	)
	(segment
		(start 310.728868 -264.08634)
		(end 307.496464 -264.08634)
		(width 0.18288)
		(layer "In4.Cu")
		(net "M_C_CPU0_SA_CA<0>")
	)
	(segment
		(start 283.644086 -266.590526)
		(end 282.795218 -265.741658)
		(width 0.18288)
		(layer "In4.Cu")
		(net "M_C_CPU0_SA_CA<0>")
	)
	(segment
		(start 312.761122 -262.83285)
		(end 312.263028 -263.330944)
		(width 0.18288)
		(layer "In4.Cu")
		(net "M_C_CPU0_SA_CA<0>")
	)
	(segment
		(start 330.576174 -257.8481)
		(end 323.684646 -257.8481)
		(width 0.18288)
		(layer "In4.Cu")
		(net "M_C_CPU0_SA_CA<0>")
	)
	(segment
		(start 311.484264 -263.330944)
		(end 310.728868 -264.08634)
		(width 0.18288)
		(layer "In4.Cu")
		(net "M_C_CPU0_SA_CA<0>")
	)
	(segment
		(start 332.375002 -256.907792)
		(end 331.516482 -256.907792)
		(width 0.18288)
		(layer "In4.Cu")
		(net "M_C_CPU0_SA_CA<0>")
	)
	(segment
		(start 307.496464 -264.08634)
		(end 307.34381 -263.933686)
		(width 0.18288)
		(layer "In4.Cu")
		(net "M_C_CPU0_SA_CA<0>")
	)
	(segment
		(start 314.45835 -262.129778)
		(end 312.761122 -262.83285)
		(width 0.18288)
		(layer "In4.Cu")
		(net "M_C_CPU0_SA_CA<0>")
	)
	(segment
		(start 332.939136 -256.907792)
		(end 332.375002 -256.907792)
		(width 0.088646)
		(layer "In4.Cu")
		(net "M_C_CPU0_SA_CA<0>")
	)
	(segment
		(start 287.062164 -266.590526)
		(end 283.644086 -266.590526)
		(width 0.18288)
		(layer "In4.Cu")
		(net "M_C_CPU0_SA_CA<0>")
	)
	(segment
		(start 339.21065 -256.855976)
		(end 339.20176 -256.850896)
		(width 0.088646)
		(layer "In4.Cu")
		(net "M_C_CPU0_SA_CA<0>")
	)
	(segment
		(start 333.046578 -256.80035)
		(end 332.939136 -256.907792)
		(width 0.088646)
		(layer "In4.Cu")
		(net "M_C_CPU0_SA_CA<0>")
	)
	(segment
		(start 315.243464 -261.344664)
		(end 314.45835 -262.129778)
		(width 0.18288)
		(layer "In4.Cu")
		(net "M_C_CPU0_SA_CA<0>")
	)
	(segment
		(start 282.795218 -265.741658)
		(end 280.241756 -265.741658)
		(width 0.18288)
		(layer "In4.Cu")
		(net "M_C_CPU0_SA_CA<0>")
	)
	(segment
		(start 331.516482 -256.907792)
		(end 330.576174 -257.8481)
		(width 0.18288)
		(layer "In4.Cu")
		(net "M_C_CPU0_SA_CA<0>")
	)
	(arc
		(start 334.128364 -256.850896)
		(mid 333.845662 -256.926672)
		(end 333.56296 -256.850896)
		(width 0.088646)
		(layer "In4.Cu")
		(net "M_C_CPU0_SA_CA<0>")
	)
	(arc
		(start 336.007964 -256.850896)
		(mid 335.725262 -256.926672)
		(end 335.44256 -256.850896)
		(width 0.088646)
		(layer "In4.Cu")
		(net "M_C_CPU0_SA_CA<0>")
	)
	(arc
		(start 338.26196 -256.850896)
		(mid 338.074762 -256.800753)
		(end 337.887564 -256.850896)
		(width 0.088646)
		(layer "In4.Cu")
		(net "M_C_CPU0_SA_CA<0>")
	)
	(arc
		(start 338.827364 -256.850896)
		(mid 338.544662 -256.926672)
		(end 338.26196 -256.850896)
		(width 0.088646)
		(layer "In4.Cu")
		(net "M_C_CPU0_SA_CA<0>")
	)
	(arc
		(start 335.068164 -256.850896)
		(mid 334.785462 -256.926672)
		(end 334.50276 -256.850896)
		(width 0.088646)
		(layer "In4.Cu")
		(net "M_C_CPU0_SA_CA<0>")
	)
	(arc
		(start 337.32216 -256.850896)
		(mid 337.134962 -256.800753)
		(end 336.947764 -256.850896)
		(width 0.088646)
		(layer "In4.Cu")
		(net "M_C_CPU0_SA_CA<0>")
	)
	(arc
		(start 336.947764 -256.850896)
		(mid 336.665062 -256.926672)
		(end 336.38236 -256.850896)
		(width 0.088646)
		(layer "In4.Cu")
		(net "M_C_CPU0_SA_CA<0>")
	)
	(arc
		(start 339.389212 -257.175254)
		(mid 339.341533 -256.992354)
		(end 339.21065 -256.855976)
		(width 0.088646)
		(layer "In4.Cu")
		(net "M_C_CPU0_SA_CA<0>")
	)
	(arc
		(start 333.56296 -256.850896)
		(mid 333.472688 -256.813297)
		(end 333.375762 -256.80035)
		(width 0.088646)
		(layer "In4.Cu")
		(net "M_C_CPU0_SA_CA<0>")
	)
	(arc
		(start 335.44256 -256.850896)
		(mid 335.255362 -256.800753)
		(end 335.068164 -256.850896)
		(width 0.088646)
		(layer "In4.Cu")
		(net "M_C_CPU0_SA_CA<0>")
	)
	(arc
		(start 337.887564 -256.850896)
		(mid 337.604862 -256.926672)
		(end 337.32216 -256.850896)
		(width 0.088646)
		(layer "In4.Cu")
		(net "M_C_CPU0_SA_CA<0>")
	)
	(arc
		(start 339.20176 -256.850896)
		(mid 339.014562 -256.800753)
		(end 338.827364 -256.850896)
		(width 0.088646)
		(layer "In4.Cu")
		(net "M_C_CPU0_SA_CA<0>")
	)
	(arc
		(start 339.484462 -257.98907)
		(mid 339.413106 -257.58494)
		(end 339.389212 -257.175254)
		(width 0.088646)
		(layer "In4.Cu")
		(net "M_C_CPU0_SA_CA<0>")
	)
	(arc
		(start 336.38236 -256.850896)
		(mid 336.195162 -256.800753)
		(end 336.007964 -256.850896)
		(width 0.088646)
		(layer "In4.Cu")
		(net "M_C_CPU0_SA_CA<0>")
	)
	(arc
		(start 334.50276 -256.850896)
		(mid 334.315562 -256.800753)
		(end 334.128364 -256.850896)
		(width 0.088646)
		(layer "In4.Cu")
		(net "M_C_CPU0_SA_CA<0>")
	)
	(segment
		(start 345.593162 -255.547368)
		(end 345.593416 -255.547622)
		(width 0.20066)
		(layer "F.Cu")
		(net "M_C_CPU0_CLK_DP<1>")
	)
	(segment
		(start 345.593162 -255.011682)
		(end 345.593162 -255.547368)
		(width 0.20066)
		(layer "F.Cu")
		(net "M_C_CPU0_CLK_DP<1>")
	)
	(segment
		(start 283.916882 -260.21665)
		(end 282.811982 -260.21665)
		(width 0.20066)
		(layer "F.Cu")
		(net "M_C_CPU0_CLK_DP<1>")
	)
	(segment
		(start 341.090504 -255.228344)
		(end 341.081614 -255.223264)
		(width 0.088646)
		(layer "In4.Cu")
		(net "M_C_CPU0_CLK_DP<1>")
	)
	(segment
		(start 342.021414 -256.850896)
		(end 342.009222 -256.843784)
		(width 0.088646)
		(layer "In4.Cu")
		(net "M_C_CPU0_CLK_DP<1>")
	)
	(segment
		(start 345.593416 -255.547622)
		(end 345.280742 -255.547622)
		(width 0.088646)
		(layer "In4.Cu")
		(net "M_C_CPU0_CLK_DP<1>")
	)
	(segment
		(start 284.198314 -259.935218)
		(end 283.916882 -260.21665)
		(width 0.18288)
		(layer "In4.Cu")
		(net "M_C_CPU0_CLK_DP<1>")
	)
	(segment
		(start 315.801248 -255.16586)
		(end 314.339986 -256.627122)
		(width 0.18288)
		(layer "In4.Cu")
		(net "M_C_CPU0_CLK_DP<1>")
	)
	(segment
		(start 344.936064 -256.03708)
		(end 344.929206 -256.04089)
		(width 0.088646)
		(layer "In4.Cu")
		(net "M_C_CPU0_CLK_DP<1>")
	)
	(segment
		(start 342.975946 -256.859532)
		(end 342.961214 -256.850896)
		(width 0.088646)
		(layer "In4.Cu")
		(net "M_C_CPU0_CLK_DP<1>")
	)
	(segment
		(start 344.748612 -256.361438)
		(end 344.748612 -256.376932)
		(width 0.088646)
		(layer "In4.Cu")
		(net "M_C_CPU0_CLK_DP<1>")
	)
	(segment
		(start 340.62035 -254.414274)
		(end 340.612476 -254.409702)
		(width 0.088646)
		(layer "In4.Cu")
		(net "M_C_CPU0_CLK_DP<1>")
	)
	(segment
		(start 289.587178 -257.90271)
		(end 287.515808 -257.90271)
		(width 0.18288)
		(layer "In4.Cu")
		(net "M_C_CPU0_CLK_DP<1>")
	)
	(segment
		(start 285.385764 -259.586476)
		(end 284.543754 -259.935218)
		(width 0.18288)
		(layer "In4.Cu")
		(net "M_C_CPU0_CLK_DP<1>")
	)
	(segment
		(start 341.56015 -256.04216)
		(end 341.552276 -256.037588)
		(width 0.088646)
		(layer "In4.Cu")
		(net "M_C_CPU0_CLK_DP<1>")
	)
	(segment
		(start 344.94216 -256.033524)
		(end 344.936826 -256.036572)
		(width 0.088646)
		(layer "In4.Cu")
		(net "M_C_CPU0_CLK_DP<1>")
	)
	(segment
		(start 340.612476 -254.409702)
		(end 340.61146 -254.409194)
		(width 0.088646)
		(layer "In4.Cu")
		(net "M_C_CPU0_CLK_DP<1>")
	)
	(segment
		(start 306.359306 -256.627122)
		(end 289.587178 -257.90271)
		(width 0.18288)
		(layer "In4.Cu")
		(net "M_C_CPU0_CLK_DP<1>")
	)
	(segment
		(start 341.269066 -255.563116)
		(end 341.269066 -255.547622)
		(width 0.088646)
		(layer "In4.Cu")
		(net "M_C_CPU0_CLK_DP<1>")
	)
	(segment
		(start 327.588372 -255.16586)
		(end 315.801248 -255.16586)
		(width 0.18288)
		(layer "In4.Cu")
		(net "M_C_CPU0_CLK_DP<1>")
	)
	(segment
		(start 340.798912 -254.747776)
		(end 340.798912 -254.733552)
		(width 0.088646)
		(layer "In4.Cu")
		(net "M_C_CPU0_CLK_DP<1>")
	)
	(segment
		(start 340.269576 -252.734064)
		(end 340.061042 -252.52553)
		(width 0.18288)
		(layer "In4.Cu")
		(net "M_C_CPU0_CLK_DP<1>")
	)
	(segment
		(start 340.269576 -253.035562)
		(end 340.269576 -252.734064)
		(width 0.18288)
		(layer "In4.Cu")
		(net "M_C_CPU0_CLK_DP<1>")
	)
	(segment
		(start 284.543754 -259.935218)
		(end 284.198314 -259.935218)
		(width 0.18288)
		(layer "In4.Cu")
		(net "M_C_CPU0_CLK_DP<1>")
	)
	(segment
		(start 340.269576 -253.05893)
		(end 340.269576 -253.035562)
		(width 0.088646)
		(layer "In4.Cu")
		(net "M_C_CPU0_CLK_DP<1>")
	)
	(segment
		(start 340.061042 -252.52553)
		(end 330.228702 -252.52553)
		(width 0.18288)
		(layer "In4.Cu")
		(net "M_C_CPU0_CLK_DP<1>")
	)
	(segment
		(start 287.515808 -257.90271)
		(end 286.754062 -258.218432)
		(width 0.18288)
		(layer "In4.Cu")
		(net "M_C_CPU0_CLK_DP<1>")
	)
	(segment
		(start 341.552276 -256.037588)
		(end 341.55126 -256.03708)
		(width 0.088646)
		(layer "In4.Cu")
		(net "M_C_CPU0_CLK_DP<1>")
	)
	(segment
		(start 314.339986 -256.627122)
		(end 306.359306 -256.627122)
		(width 0.18288)
		(layer "In4.Cu")
		(net "M_C_CPU0_CLK_DP<1>")
	)
	(segment
		(start 340.329266 -253.11862)
		(end 340.269576 -253.05893)
		(width 0.088646)
		(layer "In4.Cu")
		(net "M_C_CPU0_CLK_DP<1>")
	)
	(segment
		(start 340.329266 -253.93523)
		(end 340.329266 -253.11862)
		(width 0.088646)
		(layer "In4.Cu")
		(net "M_C_CPU0_CLK_DP<1>")
	)
	(segment
		(start 343.915746 -256.859532)
		(end 343.901014 -256.850896)
		(width 0.088646)
		(layer "In4.Cu")
		(net "M_C_CPU0_CLK_DP<1>")
	)
	(segment
		(start 330.228702 -252.52553)
		(end 327.588372 -255.16586)
		(width 0.18288)
		(layer "In4.Cu")
		(net "M_C_CPU0_CLK_DP<1>")
	)
	(segment
		(start 345.280742 -255.547622)
		(end 345.214956 -255.613408)
		(width 0.088646)
		(layer "In4.Cu")
		(net "M_C_CPU0_CLK_DP<1>")
	)
	(segment
		(start 286.754062 -258.218432)
		(end 285.385764 -259.586476)
		(width 0.18288)
		(layer "In4.Cu")
		(net "M_C_CPU0_CLK_DP<1>")
	)
	(segment
		(start 344.929206 -256.04089)
		(end 344.927174 -256.04216)
		(width 0.088646)
		(layer "In4.Cu")
		(net "M_C_CPU0_CLK_DP<1>")
	)
	(segment
		(start 344.936826 -256.036572)
		(end 344.936064 -256.03708)
		(width 0.088646)
		(layer "In4.Cu")
		(net "M_C_CPU0_CLK_DP<1>")
	)
	(arc
		(start 344.466418 -256.850896)
		(mid 344.192219 -256.926731)
		(end 343.915746 -256.859532)
		(width 0.088646)
		(layer "In4.Cu")
		(net "M_C_CPU0_CLK_DP<1>")
	)
	(arc
		(start 343.526618 -256.850896)
		(mid 343.252419 -256.926731)
		(end 342.975946 -256.859532)
		(width 0.088646)
		(layer "In4.Cu")
		(net "M_C_CPU0_CLK_DP<1>")
	)
	(arc
		(start 345.212162 -255.634236)
		(mid 345.121898 -255.864146)
		(end 344.94216 -256.033524)
		(width 0.088646)
		(layer "In4.Cu")
		(net "M_C_CPU0_CLK_DP<1>")
	)
	(arc
		(start 342.586818 -256.850896)
		(mid 342.304116 -256.926672)
		(end 342.021414 -256.850896)
		(width 0.088646)
		(layer "In4.Cu")
		(net "M_C_CPU0_CLK_DP<1>")
	)
	(arc
		(start 344.927174 -256.04216)
		(mid 344.79626 -256.17852)
		(end 344.748612 -256.361438)
		(width 0.088646)
		(layer "In4.Cu")
		(net "M_C_CPU0_CLK_DP<1>")
	)
	(arc
		(start 344.748612 -256.376932)
		(mid 344.669242 -256.650666)
		(end 344.466418 -256.850896)
		(width 0.088646)
		(layer "In4.Cu")
		(net "M_C_CPU0_CLK_DP<1>")
	)
	(arc
		(start 340.61146 -254.409194)
		(mid 340.408637 -254.208963)
		(end 340.329266 -253.93523)
		(width 0.088646)
		(layer "In4.Cu")
		(net "M_C_CPU0_CLK_DP<1>")
	)
	(arc
		(start 340.798912 -254.733552)
		(mid 340.751233 -254.550652)
		(end 340.62035 -254.414274)
		(width 0.088646)
		(layer "In4.Cu")
		(net "M_C_CPU0_CLK_DP<1>")
	)
	(arc
		(start 342.009222 -256.843784)
		(mid 341.810994 -256.637936)
		(end 341.738712 -256.361438)
		(width 0.088646)
		(layer "In4.Cu")
		(net "M_C_CPU0_CLK_DP<1>")
	)
	(arc
		(start 343.901014 -256.850896)
		(mid 343.713816 -256.800753)
		(end 343.526618 -256.850896)
		(width 0.088646)
		(layer "In4.Cu")
		(net "M_C_CPU0_CLK_DP<1>")
	)
	(arc
		(start 345.214956 -255.613408)
		(mid 345.213655 -255.623835)
		(end 345.212162 -255.634236)
		(width 0.088646)
		(layer "In4.Cu")
		(net "M_C_CPU0_CLK_DP<1>")
	)
	(arc
		(start 341.269066 -255.547622)
		(mid 341.221387 -255.364722)
		(end 341.090504 -255.228344)
		(width 0.088646)
		(layer "In4.Cu")
		(net "M_C_CPU0_CLK_DP<1>")
	)
	(arc
		(start 341.738712 -256.361438)
		(mid 341.691033 -256.178538)
		(end 341.56015 -256.04216)
		(width 0.088646)
		(layer "In4.Cu")
		(net "M_C_CPU0_CLK_DP<1>")
	)
	(arc
		(start 341.55126 -256.03708)
		(mid 341.348437 -255.836849)
		(end 341.269066 -255.563116)
		(width 0.088646)
		(layer "In4.Cu")
		(net "M_C_CPU0_CLK_DP<1>")
	)
	(arc
		(start 341.081614 -255.223264)
		(mid 340.878133 -255.02246)
		(end 340.798912 -254.747776)
		(width 0.088646)
		(layer "In4.Cu")
		(net "M_C_CPU0_CLK_DP<1>")
	)
	(arc
		(start 342.961214 -256.850896)
		(mid 342.774016 -256.800753)
		(end 342.586818 -256.850896)
		(width 0.088646)
		(layer "In4.Cu")
		(net "M_C_CPU0_CLK_DP<1>")
	)
	(segment
		(start 343.713562 -255.547368)
		(end 343.713816 -255.547622)
		(width 0.20066)
		(layer "F.Cu")
		(net "M_C_CPU0_CLK_DP<0>")
	)
	(segment
		(start 343.713562 -255.011682)
		(end 343.713562 -255.547368)
		(width 0.20066)
		(layer "F.Cu")
		(net "M_C_CPU0_CLK_DP<0>")
	)
	(segment
		(start 276.373082 -260.21665)
		(end 275.268182 -260.21665)
		(width 0.20066)
		(layer "F.Cu")
		(net "M_C_CPU0_CLK_DP<0>")
	)
	(segment
		(start 342.030304 -255.228344)
		(end 342.021414 -255.223264)
		(width 0.088646)
		(layer "In4.Cu")
		(net "M_C_CPU0_CLK_DP<0>")
	)
	(segment
		(start 341.56015 -254.414274)
		(end 341.552276 -254.409702)
		(width 0.088646)
		(layer "In4.Cu")
		(net "M_C_CPU0_CLK_DP<0>")
	)
	(segment
		(start 341.209376 -253.035562)
		(end 341.209376 -252.413008)
		(width 0.18288)
		(layer "In4.Cu")
		(net "M_C_CPU0_CLK_DP<0>")
	)
	(segment
		(start 290.730432 -256.98831)
		(end 281.551634 -256.98831)
		(width 0.18288)
		(layer "In4.Cu")
		(net "M_C_CPU0_CLK_DP<0>")
	)
	(segment
		(start 343.056464 -256.03708)
		(end 343.04605 -256.043176)
		(width 0.088646)
		(layer "In4.Cu")
		(net "M_C_CPU0_CLK_DP<0>")
	)
	(segment
		(start 341.209376 -253.05893)
		(end 341.209376 -253.035562)
		(width 0.088646)
		(layer "In4.Cu")
		(net "M_C_CPU0_CLK_DP<0>")
	)
	(segment
		(start 341.552276 -254.409702)
		(end 341.55126 -254.409194)
		(width 0.088646)
		(layer "In4.Cu")
		(net "M_C_CPU0_CLK_DP<0>")
	)
	(segment
		(start 307.90388 -255.625092)
		(end 290.730432 -256.98831)
		(width 0.18288)
		(layer "In4.Cu")
		(net "M_C_CPU0_CLK_DP<0>")
	)
	(segment
		(start 276.977602 -259.935218)
		(end 276.654514 -259.935218)
		(width 0.18288)
		(layer "In4.Cu")
		(net "M_C_CPU0_CLK_DP<0>")
	)
	(segment
		(start 341.269066 -253.93523)
		(end 341.269066 -253.11862)
		(width 0.088646)
		(layer "In4.Cu")
		(net "M_C_CPU0_CLK_DP<0>")
	)
	(segment
		(start 322.39331 -254.5207)
		(end 322.129658 -254.257048)
		(width 0.18288)
		(layer "In4.Cu")
		(net "M_C_CPU0_CLK_DP<0>")
	)
	(segment
		(start 341.738712 -254.747776)
		(end 341.738712 -254.733552)
		(width 0.088646)
		(layer "In4.Cu")
		(net "M_C_CPU0_CLK_DP<0>")
	)
	(segment
		(start 341.209376 -252.413008)
		(end 340.509098 -251.71273)
		(width 0.18288)
		(layer "In4.Cu")
		(net "M_C_CPU0_CLK_DP<0>")
	)
	(segment
		(start 342.208866 -255.557528)
		(end 342.208866 -255.547622)
		(width 0.088646)
		(layer "In4.Cu")
		(net "M_C_CPU0_CLK_DP<0>")
	)
	(segment
		(start 281.551634 -256.98831)
		(end 279.682194 -257.762502)
		(width 0.18288)
		(layer "In4.Cu")
		(net "M_C_CPU0_CLK_DP<0>")
	)
	(segment
		(start 315.347096 -254.257048)
		(end 313.979052 -255.625092)
		(width 0.18288)
		(layer "In4.Cu")
		(net "M_C_CPU0_CLK_DP<0>")
	)
	(segment
		(start 326.709024 -254.5207)
		(end 322.39331 -254.5207)
		(width 0.18288)
		(layer "In4.Cu")
		(net "M_C_CPU0_CLK_DP<0>")
	)
	(segment
		(start 343.400888 -255.547622)
		(end 343.335356 -255.613154)
		(width 0.088646)
		(layer "In4.Cu")
		(net "M_C_CPU0_CLK_DP<0>")
	)
	(segment
		(start 343.057226 -256.036572)
		(end 343.056464 -256.03708)
		(width 0.088646)
		(layer "In4.Cu")
		(net "M_C_CPU0_CLK_DP<0>")
	)
	(segment
		(start 279.682194 -257.762502)
		(end 277.88616 -259.558536)
		(width 0.18288)
		(layer "In4.Cu")
		(net "M_C_CPU0_CLK_DP<0>")
	)
	(segment
		(start 313.979052 -255.625092)
		(end 307.90388 -255.625092)
		(width 0.18288)
		(layer "In4.Cu")
		(net "M_C_CPU0_CLK_DP<0>")
	)
	(segment
		(start 327.278492 -254.332994)
		(end 326.709024 -254.5207)
		(width 0.18288)
		(layer "In4.Cu")
		(net "M_C_CPU0_CLK_DP<0>")
	)
	(segment
		(start 276.654514 -259.935218)
		(end 276.373082 -260.21665)
		(width 0.18288)
		(layer "In4.Cu")
		(net "M_C_CPU0_CLK_DP<0>")
	)
	(segment
		(start 343.713816 -255.547622)
		(end 343.400888 -255.547622)
		(width 0.088646)
		(layer "In4.Cu")
		(net "M_C_CPU0_CLK_DP<0>")
	)
	(segment
		(start 277.88616 -259.558536)
		(end 276.977602 -259.935218)
		(width 0.18288)
		(layer "In4.Cu")
		(net "M_C_CPU0_CLK_DP<0>")
	)
	(segment
		(start 322.129658 -254.257048)
		(end 315.347096 -254.257048)
		(width 0.18288)
		(layer "In4.Cu")
		(net "M_C_CPU0_CLK_DP<0>")
	)
	(segment
		(start 341.269066 -253.11862)
		(end 341.209376 -253.05893)
		(width 0.088646)
		(layer "In4.Cu")
		(net "M_C_CPU0_CLK_DP<0>")
	)
	(segment
		(start 329.898756 -251.71273)
		(end 327.278492 -254.332994)
		(width 0.18288)
		(layer "In4.Cu")
		(net "M_C_CPU0_CLK_DP<0>")
	)
	(segment
		(start 340.509098 -251.71273)
		(end 329.898756 -251.71273)
		(width 0.18288)
		(layer "In4.Cu")
		(net "M_C_CPU0_CLK_DP<0>")
	)
	(segment
		(start 343.06256 -256.033524)
		(end 343.057226 -256.036572)
		(width 0.088646)
		(layer "In4.Cu")
		(net "M_C_CPU0_CLK_DP<0>")
	)
	(arc
		(start 343.335356 -255.613154)
		(mid 343.248112 -255.855242)
		(end 343.06256 -256.033524)
		(width 0.088646)
		(layer "In4.Cu")
		(net "M_C_CPU0_CLK_DP<0>")
	)
	(arc
		(start 341.55126 -254.409194)
		(mid 341.348437 -254.208963)
		(end 341.269066 -253.93523)
		(width 0.088646)
		(layer "In4.Cu")
		(net "M_C_CPU0_CLK_DP<0>")
	)
	(arc
		(start 342.021414 -255.223264)
		(mid 341.817933 -255.02246)
		(end 341.738712 -254.747776)
		(width 0.088646)
		(layer "In4.Cu")
		(net "M_C_CPU0_CLK_DP<0>")
	)
	(arc
		(start 342.208866 -255.547622)
		(mid 342.161187 -255.364722)
		(end 342.030304 -255.228344)
		(width 0.088646)
		(layer "In4.Cu")
		(net "M_C_CPU0_CLK_DP<0>")
	)
	(arc
		(start 343.04605 -256.043176)
		(mid 342.767872 -256.112899)
		(end 342.491314 -256.03708)
		(width 0.088646)
		(layer "In4.Cu")
		(net "M_C_CPU0_CLK_DP<0>")
	)
	(arc
		(start 341.738712 -254.733552)
		(mid 341.691033 -254.550652)
		(end 341.56015 -254.414274)
		(width 0.088646)
		(layer "In4.Cu")
		(net "M_C_CPU0_CLK_DP<0>")
	)
	(arc
		(start 342.491314 -256.03708)
		(mid 342.286979 -255.834475)
		(end 342.208866 -255.557528)
		(width 0.088646)
		(layer "In4.Cu")
		(net "M_C_CPU0_CLK_DP<0>")
	)
	(segment
		(start 283.916882 -259.366766)
		(end 282.811982 -259.366766)
		(width 0.20066)
		(layer "F.Cu")
		(net "M_C_CPU0_CLK_DN<1>")
	)
	(segment
		(start 344.653362 -255.547368)
		(end 344.653616 -255.547622)
		(width 0.20066)
		(layer "F.Cu")
		(net "M_C_CPU0_CLK_DN<1>")
	)
	(segment
		(start 344.653362 -255.011682)
		(end 344.653362 -255.547368)
		(width 0.20066)
		(layer "F.Cu")
		(net "M_C_CPU0_CLK_DN<1>")
	)
	(segment
		(start 344.849704 -255.8669)
		(end 344.842338 -255.871218)
		(width 0.088646)
		(layer "In4.Cu")
		(net "M_C_CPU0_CLK_DN<1>")
	)
	(segment
		(start 341.647018 -255.87198)
		(end 341.638128 -255.8669)
		(width 0.088646)
		(layer "In4.Cu")
		(net "M_C_CPU0_CLK_DN<1>")
	)
	(segment
		(start 343.996264 -256.685796)
		(end 343.981532 -256.67716)
		(width 0.088646)
		(layer "In4.Cu")
		(net "M_C_CPU0_CLK_DN<1>")
	)
	(segment
		(start 306.347368 -256.317242)
		(end 289.57524 -257.59283)
		(width 0.18288)
		(layer "In4.Cu")
		(net "M_C_CPU0_CLK_DN<1>")
	)
	(segment
		(start 344.96629 -255.547622)
		(end 345.023694 -255.605026)
		(width 0.088646)
		(layer "In4.Cu")
		(net "M_C_CPU0_CLK_DN<1>")
	)
	(segment
		(start 287.454086 -257.59283)
		(end 286.578294 -257.955542)
		(width 0.18288)
		(layer "In4.Cu")
		(net "M_C_CPU0_CLK_DN<1>")
	)
	(segment
		(start 285.209996 -259.323586)
		(end 284.482032 -259.625338)
		(width 0.18288)
		(layer "In4.Cu")
		(net "M_C_CPU0_CLK_DN<1>")
	)
	(segment
		(start 344.37955 -256.680716)
		(end 344.37066 -256.685796)
		(width 0.088646)
		(layer "In4.Cu")
		(net "M_C_CPU0_CLK_DN<1>")
	)
	(segment
		(start 289.57524 -257.59283)
		(end 287.454086 -257.59283)
		(width 0.18288)
		(layer "In4.Cu")
		(net "M_C_CPU0_CLK_DN<1>")
	)
	(segment
		(start 340.707218 -254.244094)
		(end 340.698328 -254.239014)
		(width 0.088646)
		(layer "In4.Cu")
		(net "M_C_CPU0_CLK_DN<1>")
	)
	(segment
		(start 340.989412 -254.733552)
		(end 340.989412 -254.718058)
		(width 0.088646)
		(layer "In4.Cu")
		(net "M_C_CPU0_CLK_DN<1>")
	)
	(segment
		(start 343.056464 -256.685796)
		(end 343.04605 -256.6797)
		(width 0.088646)
		(layer "In4.Cu")
		(net "M_C_CPU0_CLK_DN<1>")
	)
	(segment
		(start 342.116918 -256.685796)
		(end 342.108028 -256.680716)
		(width 0.088646)
		(layer "In4.Cu")
		(net "M_C_CPU0_CLK_DN<1>")
	)
	(segment
		(start 341.459566 -255.547622)
		(end 341.459566 -255.533398)
		(width 0.088646)
		(layer "In4.Cu")
		(net "M_C_CPU0_CLK_DN<1>")
	)
	(segment
		(start 340.519512 -253.118874)
		(end 340.579456 -253.05893)
		(width 0.088646)
		(layer "In4.Cu")
		(net "M_C_CPU0_CLK_DN<1>")
	)
	(segment
		(start 284.175454 -259.625338)
		(end 283.916882 -259.366766)
		(width 0.18288)
		(layer "In4.Cu")
		(net "M_C_CPU0_CLK_DN<1>")
	)
	(segment
		(start 330.100178 -252.21565)
		(end 327.459848 -254.85598)
		(width 0.18288)
		(layer "In4.Cu")
		(net "M_C_CPU0_CLK_DN<1>")
	)
	(segment
		(start 344.653616 -255.547622)
		(end 344.96629 -255.547622)
		(width 0.088646)
		(layer "In4.Cu")
		(net "M_C_CPU0_CLK_DN<1>")
	)
	(segment
		(start 344.840814 -255.87198)
		(end 344.834718 -255.875536)
		(width 0.088646)
		(layer "In4.Cu")
		(net "M_C_CPU0_CLK_DN<1>")
	)
	(segment
		(start 340.519512 -253.919482)
		(end 340.519512 -253.118874)
		(width 0.088646)
		(layer "In4.Cu")
		(net "M_C_CPU0_CLK_DN<1>")
	)
	(segment
		(start 315.672724 -254.85598)
		(end 314.211462 -256.317242)
		(width 0.18288)
		(layer "In4.Cu")
		(net "M_C_CPU0_CLK_DN<1>")
	)
	(segment
		(start 340.519766 -253.919736)
		(end 340.519512 -253.919482)
		(width 0.088646)
		(layer "In4.Cu")
		(net "M_C_CPU0_CLK_DN<1>")
	)
	(segment
		(start 340.579456 -253.035562)
		(end 340.579456 -252.60554)
		(width 0.18288)
		(layer "In4.Cu")
		(net "M_C_CPU0_CLK_DN<1>")
	)
	(segment
		(start 286.578294 -257.955542)
		(end 285.209996 -259.323586)
		(width 0.18288)
		(layer "In4.Cu")
		(net "M_C_CPU0_CLK_DN<1>")
	)
	(segment
		(start 340.579456 -252.60554)
		(end 340.189566 -252.21565)
		(width 0.18288)
		(layer "In4.Cu")
		(net "M_C_CPU0_CLK_DN<1>")
	)
	(segment
		(start 340.579456 -253.05893)
		(end 340.579456 -253.035562)
		(width 0.088646)
		(layer "In4.Cu")
		(net "M_C_CPU0_CLK_DN<1>")
	)
	(segment
		(start 327.459848 -254.85598)
		(end 315.672724 -254.85598)
		(width 0.18288)
		(layer "In4.Cu")
		(net "M_C_CPU0_CLK_DN<1>")
	)
	(segment
		(start 341.653114 -255.875536)
		(end 341.647018 -255.87198)
		(width 0.088646)
		(layer "In4.Cu")
		(net "M_C_CPU0_CLK_DN<1>")
	)
	(segment
		(start 340.189566 -252.21565)
		(end 330.100178 -252.21565)
		(width 0.18288)
		(layer "In4.Cu")
		(net "M_C_CPU0_CLK_DN<1>")
	)
	(segment
		(start 344.842338 -255.871218)
		(end 344.840814 -255.87198)
		(width 0.088646)
		(layer "In4.Cu")
		(net "M_C_CPU0_CLK_DN<1>")
	)
	(segment
		(start 314.211462 -256.317242)
		(end 306.347368 -256.317242)
		(width 0.18288)
		(layer "In4.Cu")
		(net "M_C_CPU0_CLK_DN<1>")
	)
	(segment
		(start 284.482032 -259.625338)
		(end 284.175454 -259.625338)
		(width 0.18288)
		(layer "In4.Cu")
		(net "M_C_CPU0_CLK_DN<1>")
	)
	(segment
		(start 341.176864 -255.05791)
		(end 341.167974 -255.05283)
		(width 0.088646)
		(layer "In4.Cu")
		(net "M_C_CPU0_CLK_DN<1>")
	)
	(arc
		(start 340.698328 -254.239014)
		(mid 340.567414 -254.102654)
		(end 340.519766 -253.919736)
		(width 0.088646)
		(layer "In4.Cu")
		(net "M_C_CPU0_CLK_DN<1>")
	)
	(arc
		(start 343.04605 -256.6797)
		(mid 342.767872 -256.609977)
		(end 342.491314 -256.685796)
		(width 0.088646)
		(layer "In4.Cu")
		(net "M_C_CPU0_CLK_DN<1>")
	)
	(arc
		(start 343.981532 -256.67716)
		(mid 343.705057 -256.60984)
		(end 343.43086 -256.685796)
		(width 0.088646)
		(layer "In4.Cu")
		(net "M_C_CPU0_CLK_DN<1>")
	)
	(arc
		(start 344.558112 -256.361438)
		(mid 344.510433 -256.544338)
		(end 344.37955 -256.680716)
		(width 0.088646)
		(layer "In4.Cu")
		(net "M_C_CPU0_CLK_DN<1>")
	)
	(arc
		(start 341.929466 -256.361438)
		(mid 341.85555 -256.081936)
		(end 341.653114 -255.875536)
		(width 0.088646)
		(layer "In4.Cu")
		(net "M_C_CPU0_CLK_DN<1>")
	)
	(arc
		(start 341.638128 -255.8669)
		(mid 341.507214 -255.73054)
		(end 341.459566 -255.547622)
		(width 0.088646)
		(layer "In4.Cu")
		(net "M_C_CPU0_CLK_DN<1>")
	)
	(arc
		(start 341.459566 -255.533398)
		(mid 341.380347 -255.258713)
		(end 341.176864 -255.05791)
		(width 0.088646)
		(layer "In4.Cu")
		(net "M_C_CPU0_CLK_DN<1>")
	)
	(arc
		(start 340.989412 -254.718058)
		(mid 340.910042 -254.444324)
		(end 340.707218 -254.244094)
		(width 0.088646)
		(layer "In4.Cu")
		(net "M_C_CPU0_CLK_DN<1>")
	)
	(arc
		(start 344.37066 -256.685796)
		(mid 344.183462 -256.735939)
		(end 343.996264 -256.685796)
		(width 0.088646)
		(layer "In4.Cu")
		(net "M_C_CPU0_CLK_DN<1>")
	)
	(arc
		(start 343.43086 -256.685796)
		(mid 343.243662 -256.735939)
		(end 343.056464 -256.685796)
		(width 0.088646)
		(layer "In4.Cu")
		(net "M_C_CPU0_CLK_DN<1>")
	)
	(arc
		(start 344.834718 -255.875536)
		(mid 344.632131 -256.081887)
		(end 344.558112 -256.361438)
		(width 0.088646)
		(layer "In4.Cu")
		(net "M_C_CPU0_CLK_DN<1>")
	)
	(arc
		(start 341.167974 -255.05283)
		(mid 341.03706 -254.91647)
		(end 340.989412 -254.733552)
		(width 0.088646)
		(layer "In4.Cu")
		(net "M_C_CPU0_CLK_DN<1>")
	)
	(arc
		(start 342.491314 -256.685796)
		(mid 342.304116 -256.735939)
		(end 342.116918 -256.685796)
		(width 0.088646)
		(layer "In4.Cu")
		(net "M_C_CPU0_CLK_DN<1>")
	)
	(arc
		(start 345.023694 -255.605026)
		(mid 344.965538 -255.755139)
		(end 344.849704 -255.8669)
		(width 0.088646)
		(layer "In4.Cu")
		(net "M_C_CPU0_CLK_DN<1>")
	)
	(arc
		(start 342.108028 -256.680716)
		(mid 341.977114 -256.544356)
		(end 341.929466 -256.361438)
		(width 0.088646)
		(layer "In4.Cu")
		(net "M_C_CPU0_CLK_DN<1>")
	)
	(segment
		(start 276.373082 -259.366766)
		(end 275.268182 -259.366766)
		(width 0.20066)
		(layer "F.Cu")
		(net "M_C_CPU0_CLK_DN<0>")
	)
	(segment
		(start 342.773762 -255.547368)
		(end 342.774016 -255.547622)
		(width 0.20066)
		(layer "F.Cu")
		(net "M_C_CPU0_CLK_DN<0>")
	)
	(segment
		(start 342.773762 -255.011682)
		(end 342.773762 -255.547368)
		(width 0.20066)
		(layer "F.Cu")
		(net "M_C_CPU0_CLK_DN<0>")
	)
	(segment
		(start 342.962738 -255.871218)
		(end 342.961214 -255.87198)
		(width 0.088646)
		(layer "In4.Cu")
		(net "M_C_CPU0_CLK_DN<0>")
	)
	(segment
		(start 342.116664 -255.05791)
		(end 342.107774 -255.05283)
		(width 0.088646)
		(layer "In4.Cu")
		(net "M_C_CPU0_CLK_DN<0>")
	)
	(segment
		(start 276.91588 -259.625338)
		(end 276.631654 -259.625338)
		(width 0.18288)
		(layer "In4.Cu")
		(net "M_C_CPU0_CLK_DN<0>")
	)
	(segment
		(start 276.631654 -259.625338)
		(end 276.373082 -259.366766)
		(width 0.18288)
		(layer "In4.Cu")
		(net "M_C_CPU0_CLK_DN<0>")
	)
	(segment
		(start 342.970104 -255.8669)
		(end 342.962738 -255.871218)
		(width 0.088646)
		(layer "In4.Cu")
		(net "M_C_CPU0_CLK_DN<0>")
	)
	(segment
		(start 281.489912 -256.67843)
		(end 279.506426 -257.499612)
		(width 0.18288)
		(layer "In4.Cu")
		(net "M_C_CPU0_CLK_DN<0>")
	)
	(segment
		(start 327.11136 -254.061722)
		(end 326.65924 -254.21082)
		(width 0.18288)
		(layer "In4.Cu")
		(net "M_C_CPU0_CLK_DN<0>")
	)
	(segment
		(start 341.459312 -253.118874)
		(end 341.519256 -253.05893)
		(width 0.088646)
		(layer "In4.Cu")
		(net "M_C_CPU0_CLK_DN<0>")
	)
	(segment
		(start 341.459312 -253.919482)
		(end 341.459312 -253.118874)
		(width 0.088646)
		(layer "In4.Cu")
		(net "M_C_CPU0_CLK_DN<0>")
	)
	(segment
		(start 290.717732 -256.67843)
		(end 281.489912 -256.67843)
		(width 0.18288)
		(layer "In4.Cu")
		(net "M_C_CPU0_CLK_DN<0>")
	)
	(segment
		(start 290.717986 -256.678176)
		(end 290.717732 -256.67843)
		(width 0.18288)
		(layer "In4.Cu")
		(net "M_C_CPU0_CLK_DN<0>")
	)
	(segment
		(start 341.519256 -253.035562)
		(end 341.519256 -252.284484)
		(width 0.18288)
		(layer "In4.Cu")
		(net "M_C_CPU0_CLK_DN<0>")
	)
	(segment
		(start 277.710392 -259.295646)
		(end 276.91588 -259.625338)
		(width 0.18288)
		(layer "In4.Cu")
		(net "M_C_CPU0_CLK_DN<0>")
	)
	(segment
		(start 307.891434 -255.315212)
		(end 290.717986 -256.678176)
		(width 0.18288)
		(layer "In4.Cu")
		(net "M_C_CPU0_CLK_DN<0>")
	)
	(segment
		(start 313.850528 -255.315212)
		(end 307.891434 -255.315212)
		(width 0.18288)
		(layer "In4.Cu")
		(net "M_C_CPU0_CLK_DN<0>")
	)
	(segment
		(start 341.459566 -253.919736)
		(end 341.459312 -253.919482)
		(width 0.088646)
		(layer "In4.Cu")
		(net "M_C_CPU0_CLK_DN<0>")
	)
	(segment
		(start 341.647018 -254.244094)
		(end 341.638128 -254.239014)
		(width 0.088646)
		(layer "In4.Cu")
		(net "M_C_CPU0_CLK_DN<0>")
	)
	(segment
		(start 342.399366 -255.547622)
		(end 342.399366 -255.533398)
		(width 0.088646)
		(layer "In4.Cu")
		(net "M_C_CPU0_CLK_DN<0>")
	)
	(segment
		(start 329.770232 -251.40285)
		(end 327.11136 -254.061722)
		(width 0.18288)
		(layer "In4.Cu")
		(net "M_C_CPU0_CLK_DN<0>")
	)
	(segment
		(start 340.637622 -251.40285)
		(end 329.770232 -251.40285)
		(width 0.18288)
		(layer "In4.Cu")
		(net "M_C_CPU0_CLK_DN<0>")
	)
	(segment
		(start 342.774016 -255.547622)
		(end 343.086944 -255.547622)
		(width 0.088646)
		(layer "In4.Cu")
		(net "M_C_CPU0_CLK_DN<0>")
	)
	(segment
		(start 341.519256 -253.05893)
		(end 341.519256 -253.035562)
		(width 0.088646)
		(layer "In4.Cu")
		(net "M_C_CPU0_CLK_DN<0>")
	)
	(segment
		(start 341.519256 -252.284484)
		(end 340.637622 -251.40285)
		(width 0.18288)
		(layer "In4.Cu")
		(net "M_C_CPU0_CLK_DN<0>")
	)
	(segment
		(start 322.258182 -253.947168)
		(end 315.218572 -253.947168)
		(width 0.18288)
		(layer "In4.Cu")
		(net "M_C_CPU0_CLK_DN<0>")
	)
	(segment
		(start 342.586818 -255.87198)
		(end 342.577928 -255.8669)
		(width 0.088646)
		(layer "In4.Cu")
		(net "M_C_CPU0_CLK_DN<0>")
	)
	(segment
		(start 279.506426 -257.499612)
		(end 277.710392 -259.295646)
		(width 0.18288)
		(layer "In4.Cu")
		(net "M_C_CPU0_CLK_DN<0>")
	)
	(segment
		(start 322.521834 -254.21082)
		(end 322.258182 -253.947168)
		(width 0.18288)
		(layer "In4.Cu")
		(net "M_C_CPU0_CLK_DN<0>")
	)
	(segment
		(start 315.218572 -253.947168)
		(end 313.850528 -255.315212)
		(width 0.18288)
		(layer "In4.Cu")
		(net "M_C_CPU0_CLK_DN<0>")
	)
	(segment
		(start 326.65924 -254.21082)
		(end 322.521834 -254.21082)
		(width 0.18288)
		(layer "In4.Cu")
		(net "M_C_CPU0_CLK_DN<0>")
	)
	(segment
		(start 341.929212 -254.733552)
		(end 341.929212 -254.718058)
		(width 0.088646)
		(layer "In4.Cu")
		(net "M_C_CPU0_CLK_DN<0>")
	)
	(segment
		(start 343.086944 -255.547622)
		(end 343.144094 -255.604772)
		(width 0.088646)
		(layer "In4.Cu")
		(net "M_C_CPU0_CLK_DN<0>")
	)
	(arc
		(start 342.399366 -255.533398)
		(mid 342.320147 -255.258713)
		(end 342.116664 -255.05791)
		(width 0.088646)
		(layer "In4.Cu")
		(net "M_C_CPU0_CLK_DN<0>")
	)
	(arc
		(start 342.107774 -255.05283)
		(mid 341.97686 -254.91647)
		(end 341.929212 -254.733552)
		(width 0.088646)
		(layer "In4.Cu")
		(net "M_C_CPU0_CLK_DN<0>")
	)
	(arc
		(start 343.144094 -255.604772)
		(mid 343.085975 -255.755013)
		(end 342.970104 -255.8669)
		(width 0.088646)
		(layer "In4.Cu")
		(net "M_C_CPU0_CLK_DN<0>")
	)
	(arc
		(start 341.929212 -254.718058)
		(mid 341.849842 -254.444324)
		(end 341.647018 -254.244094)
		(width 0.088646)
		(layer "In4.Cu")
		(net "M_C_CPU0_CLK_DN<0>")
	)
	(arc
		(start 342.961214 -255.87198)
		(mid 342.774016 -255.922123)
		(end 342.586818 -255.87198)
		(width 0.088646)
		(layer "In4.Cu")
		(net "M_C_CPU0_CLK_DN<0>")
	)
	(arc
		(start 341.638128 -254.239014)
		(mid 341.507214 -254.102654)
		(end 341.459566 -253.919736)
		(width 0.088646)
		(layer "In4.Cu")
		(net "M_C_CPU0_CLK_DN<0>")
	)
	(arc
		(start 342.577928 -255.8669)
		(mid 342.447014 -255.73054)
		(end 342.399366 -255.547622)
		(width 0.088646)
		(layer "In4.Cu")
		(net "M_C_CPU0_CLK_DN<0>")
	)
	(segment
		(start 274.152868 -269.141702)
		(end 274.143978 -269.132812)
		(width 0.1016)
		(layer "F.Cu")
		(net "M_C_CPU0_ALERT_N")
	)
	(segment
		(start 279.816814 -269.566644)
		(end 278.711914 -269.566644)
		(width 0.20066)
		(layer "F.Cu")
		(net "M_C_CPU0_ALERT_N")
	)
	(segment
		(start 349.352362 -253.383796)
		(end 349.352362 -253.919482)
		(width 0.20066)
		(layer "F.Cu")
		(net "M_C_CPU0_ALERT_N")
	)
	(segment
		(start 277.072598 -269.566644)
		(end 276.647656 -269.141702)
		(width 0.20066)
		(layer "F.Cu")
		(net "M_C_CPU0_ALERT_N")
	)
	(segment
		(start 273.218148 -269.777972)
		(end 272.713704 -269.777972)
		(width 0.20066)
		(layer "F.Cu")
		(net "M_C_CPU0_ALERT_N")
	)
	(segment
		(start 273.37258 -269.62354)
		(end 273.218148 -269.777972)
		(width 0.20066)
		(layer "F.Cu")
		(net "M_C_CPU0_ALERT_N")
	)
	(segment
		(start 272.502376 -269.566644)
		(end 271.168114 -269.566644)
		(width 0.20066)
		(layer "F.Cu")
		(net "M_C_CPU0_ALERT_N")
	)
	(segment
		(start 273.37258 -269.295372)
		(end 273.37258 -269.62354)
		(width 0.20066)
		(layer "F.Cu")
		(net "M_C_CPU0_ALERT_N")
	)
	(segment
		(start 276.647656 -269.141702)
		(end 276.469094 -269.141702)
		(width 0.20066)
		(layer "F.Cu")
		(net "M_C_CPU0_ALERT_N")
	)
	(segment
		(start 273.53514 -269.132812)
		(end 273.37258 -269.295372)
		(width 0.20066)
		(layer "F.Cu")
		(net "M_C_CPU0_ALERT_N")
	)
	(segment
		(start 276.469094 -269.141702)
		(end 276.138386 -269.141702)
		(width 0.101854)
		(layer "F.Cu")
		(net "M_C_CPU0_ALERT_N")
	)
	(segment
		(start 349.352362 -253.919482)
		(end 349.352616 -253.919736)
		(width 0.20066)
		(layer "F.Cu")
		(net "M_C_CPU0_ALERT_N")
	)
	(segment
		(start 276.138386 -269.141702)
		(end 274.152868 -269.141702)
		(width 0.1016)
		(layer "F.Cu")
		(net "M_C_CPU0_ALERT_N")
	)
	(segment
		(start 272.713704 -269.777972)
		(end 272.502376 -269.566644)
		(width 0.20066)
		(layer "F.Cu")
		(net "M_C_CPU0_ALERT_N")
	)
	(segment
		(start 278.711914 -269.566644)
		(end 277.072598 -269.566644)
		(width 0.20066)
		(layer "F.Cu")
		(net "M_C_CPU0_ALERT_N")
	)
	(segment
		(start 274.143978 -269.132812)
		(end 273.53514 -269.132812)
		(width 0.20066)
		(layer "F.Cu")
		(net "M_C_CPU0_ALERT_N")
	)
	(via
		(at 279.816814 -269.566644)
		(size 0.4572)
		(drill 0.2032)
		(layers "F.Cu" "B.Cu")
		(net "M_C_CPU0_ALERT_N")
	)
	(via
		(at 349.352616 -253.919736)
		(size 0.4572)
		(drill 0.2032)
		(layers "F.Cu" "B.Cu")
		(net "M_C_CPU0_ALERT_N")
	)
	(segment
		(start 280.775918 -269.566644)
		(end 279.816814 -269.566644)
		(width 0.18288)
		(layer "In6.Cu")
		(net "M_C_CPU0_ALERT_N")
	)
	(segment
		(start 344.888566 -257.582162)
		(end 344.878914 -257.58775)
		(width 0.18288)
		(layer "In6.Cu")
		(net "M_C_CPU0_ALERT_N")
	)
	(segment
		(start 348.647766 -254.326644)
		(end 348.647512 -254.326644)
		(width 0.18288)
		(layer "In6.Cu")
		(net "M_C_CPU0_ALERT_N")
	)
	(segment
		(start 331.671422 -257.783584)
		(end 328.752708 -257.783584)
		(width 0.18288)
		(layer "In6.Cu")
		(net "M_C_CPU0_ALERT_N")
	)
	(segment
		(start 289.405314 -261.695438)
		(end 288.142426 -262.958326)
		(width 0.18288)
		(layer "In6.Cu")
		(net "M_C_CPU0_ALERT_N")
	)
	(segment
		(start 345.358212 -257.582162)
		(end 345.34856 -257.576574)
		(width 0.18288)
		(layer "In6.Cu")
		(net "M_C_CPU0_ALERT_N")
	)
	(segment
		(start 293.143178 -260.64083)
		(end 292.08857 -261.695438)
		(width 0.18288)
		(layer "In6.Cu")
		(net "M_C_CPU0_ALERT_N")
	)
	(segment
		(start 338.779612 -257.582162)
		(end 338.76615 -257.574288)
		(width 0.18288)
		(layer "In6.Cu")
		(net "M_C_CPU0_ALERT_N")
	)
	(segment
		(start 328.752708 -257.783584)
		(end 325.607172 -259.08635)
		(width 0.18288)
		(layer "In6.Cu")
		(net "M_C_CPU0_ALERT_N")
	)
	(segment
		(start 288.142426 -262.958326)
		(end 286.694626 -262.958326)
		(width 0.18288)
		(layer "In6.Cu")
		(net "M_C_CPU0_ALERT_N")
	)
	(segment
		(start 332.684628 -257.576574)
		(end 332.674976 -257.582162)
		(width 0.18288)
		(layer "In6.Cu")
		(net "M_C_CPU0_ALERT_N")
	)
	(segment
		(start 308.123844 -259.484622)
		(end 300.11116 -259.484622)
		(width 0.18288)
		(layer "In6.Cu")
		(net "M_C_CPU0_ALERT_N")
	)
	(segment
		(start 340.659212 -257.582162)
		(end 340.64956 -257.576574)
		(width 0.18288)
		(layer "In6.Cu")
		(net "M_C_CPU0_ALERT_N")
	)
	(segment
		(start 333.649574 -257.56108)
		(end 333.612744 -257.582162)
		(width 0.18288)
		(layer "In6.Cu")
		(net "M_C_CPU0_ALERT_N")
	)
	(segment
		(start 334.58658 -257.56235)
		(end 334.55229 -257.582162)
		(width 0.18288)
		(layer "In6.Cu")
		(net "M_C_CPU0_ALERT_N")
	)
	(segment
		(start 331.872844 -257.582162)
		(end 331.671422 -257.783584)
		(width 0.18288)
		(layer "In6.Cu")
		(net "M_C_CPU0_ALERT_N")
	)
	(segment
		(start 299.437298 -260.64083)
		(end 293.143178 -260.64083)
		(width 0.18288)
		(layer "In6.Cu")
		(net "M_C_CPU0_ALERT_N")
	)
	(segment
		(start 308.521862 -259.086604)
		(end 308.123844 -259.484622)
		(width 0.18288)
		(layer "In6.Cu")
		(net "M_C_CPU0_ALERT_N")
	)
	(segment
		(start 292.08857 -261.695438)
		(end 289.405314 -261.695438)
		(width 0.18288)
		(layer "In6.Cu")
		(net "M_C_CPU0_ALERT_N")
	)
	(segment
		(start 300.11116 -259.484622)
		(end 299.697648 -259.898134)
		(width 0.18288)
		(layer "In6.Cu")
		(net "M_C_CPU0_ALERT_N")
	)
	(segment
		(start 347.242638 -256.765552)
		(end 347.237812 -256.768346)
		(width 0.18288)
		(layer "In6.Cu")
		(net "M_C_CPU0_ALERT_N")
	)
	(segment
		(start 334.55229 -257.582162)
		(end 334.51673 -257.602736)
		(width 0.18288)
		(layer "In6.Cu")
		(net "M_C_CPU0_ALERT_N")
	)
	(segment
		(start 282.901644 -267.440918)
		(end 280.775918 -269.566644)
		(width 0.18288)
		(layer "In6.Cu")
		(net "M_C_CPU0_ALERT_N")
	)
	(segment
		(start 284.260798 -267.440918)
		(end 282.901644 -267.440918)
		(width 0.18288)
		(layer "In6.Cu")
		(net "M_C_CPU0_ALERT_N")
	)
	(segment
		(start 348.412562 -254.733552)
		(end 348.412562 -254.747014)
		(width 0.18288)
		(layer "In6.Cu")
		(net "M_C_CPU0_ALERT_N")
	)
	(segment
		(start 314.415424 -259.08635)
		(end 314.41517 -259.086604)
		(width 0.18288)
		(layer "In6.Cu")
		(net "M_C_CPU0_ALERT_N")
	)
	(segment
		(start 284.517338 -265.135614)
		(end 284.517338 -267.184378)
		(width 0.18288)
		(layer "In6.Cu")
		(net "M_C_CPU0_ALERT_N")
	)
	(segment
		(start 340.189566 -257.582162)
		(end 340.179914 -257.58775)
		(width 0.18288)
		(layer "In6.Cu")
		(net "M_C_CPU0_ALERT_N")
	)
	(segment
		(start 348.647512 -254.326644)
		(end 348.642686 -254.329438)
		(width 0.18288)
		(layer "In6.Cu")
		(net "M_C_CPU0_ALERT_N")
	)
	(segment
		(start 347.71838 -255.94818)
		(end 347.707712 -255.95453)
		(width 0.18288)
		(layer "In6.Cu")
		(net "M_C_CPU0_ALERT_N")
	)
	(segment
		(start 333.612744 -257.582162)
		(end 333.587598 -257.59664)
		(width 0.18288)
		(layer "In6.Cu")
		(net "M_C_CPU0_ALERT_N")
	)
	(segment
		(start 299.697648 -260.38048)
		(end 299.437298 -260.64083)
		(width 0.18288)
		(layer "In6.Cu")
		(net "M_C_CPU0_ALERT_N")
	)
	(segment
		(start 332.205076 -257.582162)
		(end 331.872844 -257.582162)
		(width 0.18288)
		(layer "In6.Cu")
		(net "M_C_CPU0_ALERT_N")
	)
	(segment
		(start 347.003116 -257.160776)
		(end 347.003116 -257.175254)
		(width 0.18288)
		(layer "In6.Cu")
		(net "M_C_CPU0_ALERT_N")
	)
	(segment
		(start 284.517338 -267.184378)
		(end 284.260798 -267.440918)
		(width 0.18288)
		(layer "In6.Cu")
		(net "M_C_CPU0_ALERT_N")
	)
	(segment
		(start 335.515204 -257.5687)
		(end 335.491836 -257.582162)
		(width 0.18288)
		(layer "In6.Cu")
		(net "M_C_CPU0_ALERT_N")
	)
	(segment
		(start 347.942916 -255.53797)
		(end 347.942916 -255.547622)
		(width 0.18288)
		(layer "In6.Cu")
		(net "M_C_CPU0_ALERT_N")
	)
	(segment
		(start 299.697648 -259.898134)
		(end 299.697648 -260.38048)
		(width 0.18288)
		(layer "In6.Cu")
		(net "M_C_CPU0_ALERT_N")
	)
	(segment
		(start 325.607172 -259.08635)
		(end 314.415424 -259.08635)
		(width 0.18288)
		(layer "In6.Cu")
		(net "M_C_CPU0_ALERT_N")
	)
	(segment
		(start 286.694626 -262.958326)
		(end 284.517338 -265.135614)
		(width 0.18288)
		(layer "In6.Cu")
		(net "M_C_CPU0_ALERT_N")
	)
	(segment
		(start 347.707712 -255.95453)
		(end 347.702886 -255.957324)
		(width 0.18288)
		(layer "In6.Cu")
		(net "M_C_CPU0_ALERT_N")
	)
	(segment
		(start 342.068912 -257.582162)
		(end 342.05545 -257.590036)
		(width 0.18288)
		(layer "In6.Cu")
		(net "M_C_CPU0_ALERT_N")
	)
	(segment
		(start 343.008712 -257.582162)
		(end 342.99525 -257.590036)
		(width 0.18288)
		(layer "In6.Cu")
		(net "M_C_CPU0_ALERT_N")
	)
	(segment
		(start 349.352616 -253.919736)
		(end 348.647766 -254.326644)
		(width 0.18288)
		(layer "In6.Cu")
		(net "M_C_CPU0_ALERT_N")
	)
	(segment
		(start 314.41517 -259.086604)
		(end 308.521862 -259.086604)
		(width 0.18288)
		(layer "In6.Cu")
		(net "M_C_CPU0_ALERT_N")
	)
	(segment
		(start 343.948512 -257.582162)
		(end 343.93505 -257.590036)
		(width 0.18288)
		(layer "In6.Cu")
		(net "M_C_CPU0_ALERT_N")
	)
	(segment
		(start 335.491836 -257.582162)
		(end 335.456276 -257.602736)
		(width 0.18288)
		(layer "In6.Cu")
		(net "M_C_CPU0_ALERT_N")
	)
	(segment
		(start 346.772992 -257.579368)
		(end 346.758514 -257.58775)
		(width 0.18288)
		(layer "In6.Cu")
		(net "M_C_CPU0_ALERT_N")
	)
	(arc
		(start 336.900012 -257.582162)
		(mid 336.665062 -257.519202)
		(end 336.430112 -257.582162)
		(width 0.18288)
		(layer "In6.Cu")
		(net "M_C_CPU0_ALERT_N")
	)
	(arc
		(start 347.942916 -255.547622)
		(mid 347.882961 -255.777232)
		(end 347.71838 -255.94818)
		(width 0.18288)
		(layer "In6.Cu")
		(net "M_C_CPU0_ALERT_N")
	)
	(arc
		(start 335.960212 -257.582162)
		(mid 335.739411 -257.519415)
		(end 335.515204 -257.5687)
		(width 0.18288)
		(layer "In6.Cu")
		(net "M_C_CPU0_ALERT_N")
	)
	(arc
		(start 347.472762 -256.361438)
		(mid 347.411199 -256.593961)
		(end 347.242638 -256.765552)
		(width 0.18288)
		(layer "In6.Cu")
		(net "M_C_CPU0_ALERT_N")
	)
	(arc
		(start 335.021936 -257.582162)
		(mid 334.806681 -257.518801)
		(end 334.58658 -257.56235)
		(width 0.18288)
		(layer "In6.Cu")
		(net "M_C_CPU0_ALERT_N")
	)
	(arc
		(start 341.599012 -257.582162)
		(mid 341.364062 -257.519202)
		(end 341.129112 -257.582162)
		(width 0.18288)
		(layer "In6.Cu")
		(net "M_C_CPU0_ALERT_N")
	)
	(arc
		(start 347.003116 -257.175254)
		(mid 346.941553 -257.407777)
		(end 346.772992 -257.579368)
		(width 0.18288)
		(layer "In6.Cu")
		(net "M_C_CPU0_ALERT_N")
	)
	(arc
		(start 345.34856 -257.576574)
		(mid 345.117829 -257.519213)
		(end 344.888566 -257.582162)
		(width 0.18288)
		(layer "In6.Cu")
		(net "M_C_CPU0_ALERT_N")
	)
	(arc
		(start 338.309712 -257.582162)
		(mid 338.074762 -257.645122)
		(end 337.839812 -257.582162)
		(width 0.18288)
		(layer "In6.Cu")
		(net "M_C_CPU0_ALERT_N")
	)
	(arc
		(start 332.674976 -257.582162)
		(mid 332.440026 -257.645122)
		(end 332.205076 -257.582162)
		(width 0.18288)
		(layer "In6.Cu")
		(net "M_C_CPU0_ALERT_N")
	)
	(arc
		(start 339.249512 -257.582162)
		(mid 339.014562 -257.645122)
		(end 338.779612 -257.582162)
		(width 0.18288)
		(layer "In6.Cu")
		(net "M_C_CPU0_ALERT_N")
	)
	(arc
		(start 345.828112 -257.582162)
		(mid 345.593162 -257.645122)
		(end 345.358212 -257.582162)
		(width 0.18288)
		(layer "In6.Cu")
		(net "M_C_CPU0_ALERT_N")
	)
	(arc
		(start 343.93505 -257.590036)
		(mid 343.705797 -257.64528)
		(end 343.478612 -257.582162)
		(width 0.18288)
		(layer "In6.Cu")
		(net "M_C_CPU0_ALERT_N")
	)
	(arc
		(start 346.298012 -257.582162)
		(mid 346.063062 -257.519202)
		(end 345.828112 -257.582162)
		(width 0.18288)
		(layer "In6.Cu")
		(net "M_C_CPU0_ALERT_N")
	)
	(arc
		(start 342.05545 -257.590036)
		(mid 341.826197 -257.64528)
		(end 341.599012 -257.582162)
		(width 0.18288)
		(layer "In6.Cu")
		(net "M_C_CPU0_ALERT_N")
	)
	(arc
		(start 348.642686 -254.329438)
		(mid 348.47413 -254.501032)
		(end 348.412562 -254.733552)
		(width 0.18288)
		(layer "In6.Cu")
		(net "M_C_CPU0_ALERT_N")
	)
	(arc
		(start 333.587598 -257.59664)
		(mid 333.364286 -257.644943)
		(end 333.144622 -257.582162)
		(width 0.18288)
		(layer "In6.Cu")
		(net "M_C_CPU0_ALERT_N")
	)
	(arc
		(start 347.237812 -256.768346)
		(mid 347.069508 -256.934086)
		(end 347.003116 -257.160776)
		(width 0.18288)
		(layer "In6.Cu")
		(net "M_C_CPU0_ALERT_N")
	)
	(arc
		(start 344.878914 -257.58775)
		(mid 344.647929 -257.645233)
		(end 344.418412 -257.582162)
		(width 0.18288)
		(layer "In6.Cu")
		(net "M_C_CPU0_ALERT_N")
	)
	(arc
		(start 340.179914 -257.58775)
		(mid 339.948929 -257.645233)
		(end 339.719412 -257.582162)
		(width 0.18288)
		(layer "In6.Cu")
		(net "M_C_CPU0_ALERT_N")
	)
	(arc
		(start 336.430112 -257.582162)
		(mid 336.195162 -257.645122)
		(end 335.960212 -257.582162)
		(width 0.18288)
		(layer "In6.Cu")
		(net "M_C_CPU0_ALERT_N")
	)
	(arc
		(start 337.369912 -257.582162)
		(mid 337.134962 -257.645122)
		(end 336.900012 -257.582162)
		(width 0.18288)
		(layer "In6.Cu")
		(net "M_C_CPU0_ALERT_N")
	)
	(arc
		(start 342.538812 -257.582162)
		(mid 342.303862 -257.519202)
		(end 342.068912 -257.582162)
		(width 0.18288)
		(layer "In6.Cu")
		(net "M_C_CPU0_ALERT_N")
	)
	(arc
		(start 335.456276 -257.602736)
		(mid 335.236596 -257.645565)
		(end 335.021936 -257.582162)
		(width 0.18288)
		(layer "In6.Cu")
		(net "M_C_CPU0_ALERT_N")
	)
	(arc
		(start 341.129112 -257.582162)
		(mid 340.894162 -257.645122)
		(end 340.659212 -257.582162)
		(width 0.18288)
		(layer "In6.Cu")
		(net "M_C_CPU0_ALERT_N")
	)
	(arc
		(start 334.08239 -257.582162)
		(mid 333.868553 -257.518868)
		(end 333.649574 -257.56108)
		(width 0.18288)
		(layer "In6.Cu")
		(net "M_C_CPU0_ALERT_N")
	)
	(arc
		(start 346.758514 -257.58775)
		(mid 346.527529 -257.645233)
		(end 346.298012 -257.582162)
		(width 0.18288)
		(layer "In6.Cu")
		(net "M_C_CPU0_ALERT_N")
	)
	(arc
		(start 337.839812 -257.582162)
		(mid 337.604862 -257.519202)
		(end 337.369912 -257.582162)
		(width 0.18288)
		(layer "In6.Cu")
		(net "M_C_CPU0_ALERT_N")
	)
	(arc
		(start 338.76615 -257.574288)
		(mid 338.536897 -257.519044)
		(end 338.309712 -257.582162)
		(width 0.18288)
		(layer "In6.Cu")
		(net "M_C_CPU0_ALERT_N")
	)
	(arc
		(start 343.478612 -257.582162)
		(mid 343.243662 -257.519202)
		(end 343.008712 -257.582162)
		(width 0.18288)
		(layer "In6.Cu")
		(net "M_C_CPU0_ALERT_N")
	)
	(arc
		(start 348.412562 -254.747014)
		(mid 348.346339 -254.974451)
		(end 348.177612 -255.140714)
		(width 0.18288)
		(layer "In6.Cu")
		(net "M_C_CPU0_ALERT_N")
	)
	(arc
		(start 340.64956 -257.576574)
		(mid 340.418829 -257.519213)
		(end 340.189566 -257.582162)
		(width 0.18288)
		(layer "In6.Cu")
		(net "M_C_CPU0_ALERT_N")
	)
	(arc
		(start 333.144622 -257.582162)
		(mid 332.915359 -257.519237)
		(end 332.684628 -257.576574)
		(width 0.18288)
		(layer "In6.Cu")
		(net "M_C_CPU0_ALERT_N")
	)
	(arc
		(start 342.99525 -257.590036)
		(mid 342.765997 -257.64528)
		(end 342.538812 -257.582162)
		(width 0.18288)
		(layer "In6.Cu")
		(net "M_C_CPU0_ALERT_N")
	)
	(arc
		(start 339.719412 -257.582162)
		(mid 339.484462 -257.519202)
		(end 339.249512 -257.582162)
		(width 0.18288)
		(layer "In6.Cu")
		(net "M_C_CPU0_ALERT_N")
	)
	(arc
		(start 334.51673 -257.602736)
		(mid 334.29705 -257.645565)
		(end 334.08239 -257.582162)
		(width 0.18288)
		(layer "In6.Cu")
		(net "M_C_CPU0_ALERT_N")
	)
	(arc
		(start 348.177612 -255.140714)
		(mid 348.008162 -255.30856)
		(end 347.942916 -255.53797)
		(width 0.18288)
		(layer "In6.Cu")
		(net "M_C_CPU0_ALERT_N")
	)
	(arc
		(start 347.702886 -255.957324)
		(mid 347.53433 -256.128918)
		(end 347.472762 -256.361438)
		(width 0.18288)
		(layer "In6.Cu")
		(net "M_C_CPU0_ALERT_N")
	)
	(arc
		(start 344.418412 -257.582162)
		(mid 344.183462 -257.519202)
		(end 343.948512 -257.582162)
		(width 0.18288)
		(layer "In6.Cu")
		(net "M_C_CPU0_ALERT_N")
	)
	(segment
		(start 100.472494 -253.383796)
		(end 100.472494 -253.919482)
		(width 0.20066)
		(layer "F.Cu")
		(net "M_B_CPU1_SB_RSP<1>")
	)
	(segment
		(start 100.472494 -253.919482)
		(end 100.472748 -253.919736)
		(width 0.20066)
		(layer "F.Cu")
		(net "M_B_CPU1_SB_RSP<1>")
	)
	(segment
		(start 45.859446 -243.216684)
		(end 46.964346 -243.216684)
		(width 0.20066)
		(layer "F.Cu")
		(net "M_B_CPU1_SB_RSP<1>")
	)
	(segment
		(start 54.054502 -246.367554)
		(end 53.828442 -246.367554)
		(width 0.18288)
		(layer "In6.Cu")
		(net "M_B_CPU1_SB_RSP<1>")
	)
	(segment
		(start 100.11918 -253.566168)
		(end 100.11918 -252.781308)
		(width 0.088646)
		(layer "In6.Cu")
		(net "M_B_CPU1_SB_RSP<1>")
	)
	(segment
		(start 49.615598 -244.378226)
		(end 49.441354 -244.55247)
		(width 0.18288)
		(layer "In6.Cu")
		(net "M_B_CPU1_SB_RSP<1>")
	)
	(segment
		(start 57.212484 -246.73052)
		(end 57.052464 -246.89054)
		(width 0.18288)
		(layer "In6.Cu")
		(net "M_B_CPU1_SB_RSP<1>")
	)
	(segment
		(start 59.371738 -246.89054)
		(end 58.065924 -246.89054)
		(width 0.18288)
		(layer "In6.Cu")
		(net "M_B_CPU1_SB_RSP<1>")
	)
	(segment
		(start 53.060854 -243.796058)
		(end 52.909216 -243.64442)
		(width 0.18288)
		(layer "In6.Cu")
		(net "M_B_CPU1_SB_RSP<1>")
	)
	(segment
		(start 57.745884 -246.243856)
		(end 57.372504 -246.243856)
		(width 0.18288)
		(layer "In6.Cu")
		(net "M_B_CPU1_SB_RSP<1>")
	)
	(segment
		(start 60.853066 -247.7262)
		(end 60.207398 -247.7262)
		(width 0.18288)
		(layer "In6.Cu")
		(net "M_B_CPU1_SB_RSP<1>")
	)
	(segment
		(start 57.905904 -246.403876)
		(end 57.745884 -246.243856)
		(width 0.18288)
		(layer "In6.Cu")
		(net "M_B_CPU1_SB_RSP<1>")
	)
	(segment
		(start 55.967884 -246.89054)
		(end 55.016654 -245.93931)
		(width 0.18288)
		(layer "In6.Cu")
		(net "M_B_CPU1_SB_RSP<1>")
	)
	(segment
		(start 57.212484 -246.403876)
		(end 57.212484 -246.73052)
		(width 0.18288)
		(layer "In6.Cu")
		(net "M_B_CPU1_SB_RSP<1>")
	)
	(segment
		(start 52.909216 -243.64442)
		(end 49.744376 -243.64442)
		(width 0.18288)
		(layer "In6.Cu")
		(net "M_B_CPU1_SB_RSP<1>")
	)
	(segment
		(start 66.422778 -248.71045)
		(end 64.73698 -248.012204)
		(width 0.18288)
		(layer "In6.Cu")
		(net "M_B_CPU1_SB_RSP<1>")
	)
	(segment
		(start 58.065924 -246.89054)
		(end 57.905904 -246.73052)
		(width 0.18288)
		(layer "In6.Cu")
		(net "M_B_CPU1_SB_RSP<1>")
	)
	(segment
		(start 62.184788 -248.853452)
		(end 61.646054 -248.853452)
		(width 0.18288)
		(layer "In6.Cu")
		(net "M_B_CPU1_SB_RSP<1>")
	)
	(segment
		(start 52.782724 -245.095776)
		(end 53.060854 -244.817646)
		(width 0.18288)
		(layer "In6.Cu")
		(net "M_B_CPU1_SB_RSP<1>")
	)
	(segment
		(start 100.11918 -252.781308)
		(end 100.11918 -252.32868)
		(width 0.18288)
		(layer "In6.Cu")
		(net "M_B_CPU1_SB_RSP<1>")
	)
	(segment
		(start 98.660458 -250.869958)
		(end 81.982056 -250.869958)
		(width 0.18288)
		(layer "In6.Cu")
		(net "M_B_CPU1_SB_RSP<1>")
	)
	(segment
		(start 48.300132 -244.55247)
		(end 46.964346 -243.216684)
		(width 0.18288)
		(layer "In6.Cu")
		(net "M_B_CPU1_SB_RSP<1>")
	)
	(segment
		(start 72.862694 -250.74626)
		(end 69.012308 -250.74626)
		(width 0.18288)
		(layer "In6.Cu")
		(net "M_B_CPU1_SB_RSP<1>")
	)
	(segment
		(start 53.060854 -244.817646)
		(end 53.060854 -243.796058)
		(width 0.18288)
		(layer "In6.Cu")
		(net "M_B_CPU1_SB_RSP<1>")
	)
	(segment
		(start 64.73698 -248.012204)
		(end 63.026036 -248.012204)
		(width 0.18288)
		(layer "In6.Cu")
		(net "M_B_CPU1_SB_RSP<1>")
	)
	(segment
		(start 53.828442 -246.367554)
		(end 52.782724 -245.321836)
		(width 0.18288)
		(layer "In6.Cu")
		(net "M_B_CPU1_SB_RSP<1>")
	)
	(segment
		(start 61.646054 -248.853452)
		(end 61.31814 -248.525538)
		(width 0.18288)
		(layer "In6.Cu")
		(net "M_B_CPU1_SB_RSP<1>")
	)
	(segment
		(start 79.432658 -248.32056)
		(end 75.288394 -248.32056)
		(width 0.18288)
		(layer "In6.Cu")
		(net "M_B_CPU1_SB_RSP<1>")
	)
	(segment
		(start 57.905904 -246.73052)
		(end 57.905904 -246.403876)
		(width 0.18288)
		(layer "In6.Cu")
		(net "M_B_CPU1_SB_RSP<1>")
	)
	(segment
		(start 55.016654 -245.93931)
		(end 54.482746 -245.93931)
		(width 0.18288)
		(layer "In6.Cu")
		(net "M_B_CPU1_SB_RSP<1>")
	)
	(segment
		(start 49.744376 -243.64442)
		(end 49.615598 -243.773198)
		(width 0.18288)
		(layer "In6.Cu")
		(net "M_B_CPU1_SB_RSP<1>")
	)
	(segment
		(start 49.441354 -244.55247)
		(end 48.300132 -244.55247)
		(width 0.18288)
		(layer "In6.Cu")
		(net "M_B_CPU1_SB_RSP<1>")
	)
	(segment
		(start 75.288394 -248.32056)
		(end 72.862694 -250.74626)
		(width 0.18288)
		(layer "In6.Cu")
		(net "M_B_CPU1_SB_RSP<1>")
	)
	(segment
		(start 63.026036 -248.012204)
		(end 62.184788 -248.853452)
		(width 0.18288)
		(layer "In6.Cu")
		(net "M_B_CPU1_SB_RSP<1>")
	)
	(segment
		(start 81.982056 -250.869958)
		(end 79.432658 -248.32056)
		(width 0.18288)
		(layer "In6.Cu")
		(net "M_B_CPU1_SB_RSP<1>")
	)
	(segment
		(start 69.012308 -250.74626)
		(end 68.067174 -250.354846)
		(width 0.18288)
		(layer "In6.Cu")
		(net "M_B_CPU1_SB_RSP<1>")
	)
	(segment
		(start 61.31814 -248.191274)
		(end 60.853066 -247.7262)
		(width 0.18288)
		(layer "In6.Cu")
		(net "M_B_CPU1_SB_RSP<1>")
	)
	(segment
		(start 68.067174 -250.354846)
		(end 66.422778 -248.71045)
		(width 0.18288)
		(layer "In6.Cu")
		(net "M_B_CPU1_SB_RSP<1>")
	)
	(segment
		(start 57.372504 -246.243856)
		(end 57.212484 -246.403876)
		(width 0.18288)
		(layer "In6.Cu")
		(net "M_B_CPU1_SB_RSP<1>")
	)
	(segment
		(start 54.482746 -245.93931)
		(end 54.054502 -246.367554)
		(width 0.18288)
		(layer "In6.Cu")
		(net "M_B_CPU1_SB_RSP<1>")
	)
	(segment
		(start 61.31814 -248.525538)
		(end 61.31814 -248.191274)
		(width 0.18288)
		(layer "In6.Cu")
		(net "M_B_CPU1_SB_RSP<1>")
	)
	(segment
		(start 60.207398 -247.7262)
		(end 59.371738 -246.89054)
		(width 0.18288)
		(layer "In6.Cu")
		(net "M_B_CPU1_SB_RSP<1>")
	)
	(segment
		(start 57.052464 -246.89054)
		(end 55.967884 -246.89054)
		(width 0.18288)
		(layer "In6.Cu")
		(net "M_B_CPU1_SB_RSP<1>")
	)
	(segment
		(start 49.615598 -243.773198)
		(end 49.615598 -244.378226)
		(width 0.18288)
		(layer "In6.Cu")
		(net "M_B_CPU1_SB_RSP<1>")
	)
	(segment
		(start 52.782724 -245.321836)
		(end 52.782724 -245.095776)
		(width 0.18288)
		(layer "In6.Cu")
		(net "M_B_CPU1_SB_RSP<1>")
	)
	(segment
		(start 100.11918 -252.32868)
		(end 98.660458 -250.869958)
		(width 0.18288)
		(layer "In6.Cu")
		(net "M_B_CPU1_SB_RSP<1>")
	)
	(segment
		(start 100.472748 -253.919736)
		(end 100.11918 -253.566168)
		(width 0.088646)
		(layer "In6.Cu")
		(net "M_B_CPU1_SB_RSP<1>")
	)
	(segment
		(start 100.002848 -254.197612)
		(end 100.002848 -254.733298)
		(width 0.20066)
		(layer "F.Cu")
		(net "M_B_CPU1_SB_RSP<0>")
	)
	(segment
		(start 38.315646 -243.216684)
		(end 39.420546 -243.216684)
		(width 0.20066)
		(layer "F.Cu")
		(net "M_B_CPU1_SB_RSP<0>")
	)
	(segment
		(start 100.002848 -254.733298)
		(end 100.002594 -254.733552)
		(width 0.20066)
		(layer "F.Cu")
		(net "M_B_CPU1_SB_RSP<0>")
	)
	(segment
		(start 81.759806 -251.597668)
		(end 79.153766 -248.991628)
		(width 0.18288)
		(layer "In6.Cu")
		(net "M_B_CPU1_SB_RSP<0>")
	)
	(segment
		(start 41.516554 -244.686582)
		(end 40.447722 -244.24386)
		(width 0.18288)
		(layer "In6.Cu")
		(net "M_B_CPU1_SB_RSP<0>")
	)
	(segment
		(start 51.667664 -247.040908)
		(end 50.754026 -247.040908)
		(width 0.18288)
		(layer "In6.Cu")
		(net "M_B_CPU1_SB_RSP<0>")
	)
	(segment
		(start 76.025756 -248.991628)
		(end 73.094088 -251.923296)
		(width 0.18288)
		(layer "In6.Cu")
		(net "M_B_CPU1_SB_RSP<0>")
	)
	(segment
		(start 97.71253 -251.983494)
		(end 88.032844 -251.983494)
		(width 0.18288)
		(layer "In6.Cu")
		(net "M_B_CPU1_SB_RSP<0>")
	)
	(segment
		(start 66.463926 -250.481592)
		(end 64.614552 -249.715782)
		(width 0.18288)
		(layer "In6.Cu")
		(net "M_B_CPU1_SB_RSP<0>")
	)
	(segment
		(start 67.297554 -251.31522)
		(end 66.463926 -250.481592)
		(width 0.18288)
		(layer "In6.Cu")
		(net "M_B_CPU1_SB_RSP<0>")
	)
	(segment
		(start 98.031808 -253.213108)
		(end 98.031808 -252.781308)
		(width 0.088646)
		(layer "In6.Cu")
		(net "M_B_CPU1_SB_RSP<0>")
	)
	(segment
		(start 58.78195 -249.649234)
		(end 56.466486 -249.649234)
		(width 0.18288)
		(layer "In6.Cu")
		(net "M_B_CPU1_SB_RSP<0>")
	)
	(segment
		(start 79.153766 -248.991628)
		(end 76.025756 -248.991628)
		(width 0.18288)
		(layer "In6.Cu")
		(net "M_B_CPU1_SB_RSP<0>")
	)
	(segment
		(start 64.614552 -249.715782)
		(end 63.005462 -249.715782)
		(width 0.18288)
		(layer "In6.Cu")
		(net "M_B_CPU1_SB_RSP<0>")
	)
	(segment
		(start 98.218244 -253.399544)
		(end 98.031808 -253.213108)
		(width 0.088646)
		(layer "In6.Cu")
		(net "M_B_CPU1_SB_RSP<0>")
	)
	(segment
		(start 62.103508 -250.617736)
		(end 59.750452 -250.617736)
		(width 0.18288)
		(layer "In6.Cu")
		(net "M_B_CPU1_SB_RSP<0>")
	)
	(segment
		(start 56.466486 -249.649234)
		(end 56.076596 -249.594878)
		(width 0.18288)
		(layer "In6.Cu")
		(net "M_B_CPU1_SB_RSP<0>")
	)
	(segment
		(start 40.447722 -244.24386)
		(end 39.420546 -243.216684)
		(width 0.18288)
		(layer "In6.Cu")
		(net "M_B_CPU1_SB_RSP<0>")
	)
	(segment
		(start 73.094088 -251.923296)
		(end 68.766182 -251.923296)
		(width 0.18288)
		(layer "In6.Cu")
		(net "M_B_CPU1_SB_RSP<0>")
	)
	(segment
		(start 98.218244 -253.919736)
		(end 98.218244 -253.399544)
		(width 0.088646)
		(layer "In6.Cu")
		(net "M_B_CPU1_SB_RSP<0>")
	)
	(segment
		(start 54.673246 -248.88825)
		(end 53.594254 -248.574814)
		(width 0.18288)
		(layer "In6.Cu")
		(net "M_B_CPU1_SB_RSP<0>")
	)
	(segment
		(start 98.031808 -252.781308)
		(end 98.031808 -252.302772)
		(width 0.18288)
		(layer "In6.Cu")
		(net "M_B_CPU1_SB_RSP<0>")
	)
	(segment
		(start 46.504352 -245.144544)
		(end 44.92625 -244.491002)
		(width 0.18288)
		(layer "In6.Cu")
		(net "M_B_CPU1_SB_RSP<0>")
	)
	(segment
		(start 53.594254 -248.574814)
		(end 51.667664 -247.040908)
		(width 0.18288)
		(layer "In6.Cu")
		(net "M_B_CPU1_SB_RSP<0>")
	)
	(segment
		(start 88.032844 -251.983494)
		(end 87.647018 -251.597668)
		(width 0.18288)
		(layer "In6.Cu")
		(net "M_B_CPU1_SB_RSP<0>")
	)
	(segment
		(start 50.754026 -247.040908)
		(end 49.383442 -246.43207)
		(width 0.18288)
		(layer "In6.Cu")
		(net "M_B_CPU1_SB_RSP<0>")
	)
	(segment
		(start 47.335186 -245.340886)
		(end 46.700694 -245.340886)
		(width 0.18288)
		(layer "In6.Cu")
		(net "M_B_CPU1_SB_RSP<0>")
	)
	(segment
		(start 59.750452 -250.617736)
		(end 58.78195 -249.649234)
		(width 0.18288)
		(layer "In6.Cu")
		(net "M_B_CPU1_SB_RSP<0>")
	)
	(segment
		(start 68.766182 -251.923296)
		(end 67.297554 -251.31522)
		(width 0.18288)
		(layer "In6.Cu")
		(net "M_B_CPU1_SB_RSP<0>")
	)
	(segment
		(start 63.005462 -249.715782)
		(end 62.103508 -250.617736)
		(width 0.18288)
		(layer "In6.Cu")
		(net "M_B_CPU1_SB_RSP<0>")
	)
	(segment
		(start 48.495966 -246.192294)
		(end 47.335186 -245.340886)
		(width 0.18288)
		(layer "In6.Cu")
		(net "M_B_CPU1_SB_RSP<0>")
	)
	(segment
		(start 100.002594 -254.733552)
		(end 99.511866 -254.512826)
		(width 0.088646)
		(layer "In6.Cu")
		(net "M_B_CPU1_SB_RSP<0>")
	)
	(segment
		(start 46.700694 -245.340886)
		(end 46.504352 -245.144544)
		(width 0.18288)
		(layer "In6.Cu")
		(net "M_B_CPU1_SB_RSP<0>")
	)
	(segment
		(start 42.523664 -244.491002)
		(end 42.328084 -244.686582)
		(width 0.18288)
		(layer "In6.Cu")
		(net "M_B_CPU1_SB_RSP<0>")
	)
	(segment
		(start 49.383442 -246.43207)
		(end 48.495966 -246.192294)
		(width 0.18288)
		(layer "In6.Cu")
		(net "M_B_CPU1_SB_RSP<0>")
	)
	(segment
		(start 98.031808 -252.302772)
		(end 97.71253 -251.983494)
		(width 0.18288)
		(layer "In6.Cu")
		(net "M_B_CPU1_SB_RSP<0>")
	)
	(segment
		(start 42.328084 -244.686582)
		(end 41.516554 -244.686582)
		(width 0.18288)
		(layer "In6.Cu")
		(net "M_B_CPU1_SB_RSP<0>")
	)
	(segment
		(start 44.92625 -244.491002)
		(end 42.523664 -244.491002)
		(width 0.18288)
		(layer "In6.Cu")
		(net "M_B_CPU1_SB_RSP<0>")
	)
	(segment
		(start 98.405696 -254.244094)
		(end 98.396806 -254.239014)
		(width 0.088646)
		(layer "In6.Cu")
		(net "M_B_CPU1_SB_RSP<0>")
	)
	(segment
		(start 56.076596 -249.594878)
		(end 54.673246 -248.88825)
		(width 0.18288)
		(layer "In6.Cu")
		(net "M_B_CPU1_SB_RSP<0>")
	)
	(segment
		(start 87.647018 -251.597668)
		(end 81.759806 -251.597668)
		(width 0.18288)
		(layer "In6.Cu")
		(net "M_B_CPU1_SB_RSP<0>")
	)
	(arc
		(start 98.800666 -254.302006)
		(mid 98.597697 -254.310401)
		(end 98.405696 -254.244094)
		(width 0.088646)
		(layer "In6.Cu")
		(net "M_B_CPU1_SB_RSP<0>")
	)
	(arc
		(start 99.511866 -254.512826)
		(mid 99.184101 -254.313513)
		(end 98.800666 -254.302006)
		(width 0.088646)
		(layer "In6.Cu")
		(net "M_B_CPU1_SB_RSP<0>")
	)
	(arc
		(start 98.396806 -254.239014)
		(mid 98.265892 -254.102654)
		(end 98.218244 -253.919736)
		(width 0.088646)
		(layer "In6.Cu")
		(net "M_B_CPU1_SB_RSP<0>")
	)
	(segment
		(start 47.882302 -246.61241)
		(end 47.753778 -246.740934)
		(width 0.20066)
		(layer "F.Cu")
		(net "M_B_CPU1_SB_PAR")
	)
	(segment
		(start 90.964512 -247.714262)
		(end 90.964512 -247.178576)
		(width 0.20066)
		(layer "F.Cu")
		(net "M_B_CPU1_SB_PAR")
	)
	(segment
		(start 44.112942 -246.616728)
		(end 42.415714 -246.616728)
		(width 0.20066)
		(layer "F.Cu")
		(net "M_B_CPU1_SB_PAR")
	)
	(segment
		(start 44.749466 -247.04167)
		(end 44.735242 -247.055894)
		(width 0.101854)
		(layer "F.Cu")
		(net "M_B_CPU1_SB_PAR")
	)
	(segment
		(start 44.238926 -246.742712)
		(end 44.112942 -246.616728)
		(width 0.20066)
		(layer "F.Cu")
		(net "M_B_CPU1_SB_PAR")
	)
	(segment
		(start 90.964512 -247.178576)
		(end 90.964766 -247.178322)
		(width 0.20066)
		(layer "F.Cu")
		(net "M_B_CPU1_SB_PAR")
	)
	(segment
		(start 48.935894 -246.824246)
		(end 48.489362 -246.824246)
		(width 0.20066)
		(layer "F.Cu")
		(net "M_B_CPU1_SB_PAR")
	)
	(segment
		(start 44.38142 -247.055894)
		(end 44.238926 -246.9134)
		(width 0.20066)
		(layer "F.Cu")
		(net "M_B_CPU1_SB_PAR")
	)
	(segment
		(start 49.143412 -246.616728)
		(end 48.935894 -246.824246)
		(width 0.20066)
		(layer "F.Cu")
		(net "M_B_CPU1_SB_PAR")
	)
	(segment
		(start 44.987464 -247.04167)
		(end 44.749466 -247.04167)
		(width 0.101854)
		(layer "F.Cu")
		(net "M_B_CPU1_SB_PAR")
	)
	(segment
		(start 44.238926 -246.9134)
		(end 44.238926 -246.742712)
		(width 0.20066)
		(layer "F.Cu")
		(net "M_B_CPU1_SB_PAR")
	)
	(segment
		(start 47.060358 -247.04167)
		(end 44.987464 -247.04167)
		(width 0.1016)
		(layer "F.Cu")
		(net "M_B_CPU1_SB_PAR")
	)
	(segment
		(start 47.60468 -247.04167)
		(end 47.060358 -247.04167)
		(width 0.20066)
		(layer "F.Cu")
		(net "M_B_CPU1_SB_PAR")
	)
	(segment
		(start 47.753778 -246.892572)
		(end 47.60468 -247.04167)
		(width 0.20066)
		(layer "F.Cu")
		(net "M_B_CPU1_SB_PAR")
	)
	(segment
		(start 48.489362 -246.824246)
		(end 48.277526 -246.61241)
		(width 0.20066)
		(layer "F.Cu")
		(net "M_B_CPU1_SB_PAR")
	)
	(segment
		(start 48.277526 -246.61241)
		(end 47.882302 -246.61241)
		(width 0.20066)
		(layer "F.Cu")
		(net "M_B_CPU1_SB_PAR")
	)
	(segment
		(start 44.735242 -247.055894)
		(end 44.38142 -247.055894)
		(width 0.20066)
		(layer "F.Cu")
		(net "M_B_CPU1_SB_PAR")
	)
	(segment
		(start 49.959514 -246.616728)
		(end 49.143412 -246.616728)
		(width 0.20066)
		(layer "F.Cu")
		(net "M_B_CPU1_SB_PAR")
	)
	(segment
		(start 51.064414 -246.616728)
		(end 49.959514 -246.616728)
		(width 0.20066)
		(layer "F.Cu")
		(net "M_B_CPU1_SB_PAR")
	)
	(segment
		(start 47.753778 -246.740934)
		(end 47.753778 -246.892572)
		(width 0.20066)
		(layer "F.Cu")
		(net "M_B_CPU1_SB_PAR")
	)
	(segment
		(start 62.904878 -246.419878)
		(end 62.208156 -247.1166)
		(width 0.18288)
		(layer "In2.Cu")
		(net "M_B_CPU1_SB_PAR")
	)
	(segment
		(start 60.029852 -247.052084)
		(end 59.86399 -247.217946)
		(width 0.18288)
		(layer "In2.Cu")
		(net "M_B_CPU1_SB_PAR")
	)
	(segment
		(start 83.14055 -246.565166)
		(end 74.200258 -246.565166)
		(width 0.18288)
		(layer "In2.Cu")
		(net "M_B_CPU1_SB_PAR")
	)
	(segment
		(start 56.92902 -247.382538)
		(end 56.305958 -246.759476)
		(width 0.18288)
		(layer "In2.Cu")
		(net "M_B_CPU1_SB_PAR")
	)
	(segment
		(start 70.120764 -246.360696)
		(end 69.927724 -246.553736)
		(width 0.18288)
		(layer "In2.Cu")
		(net "M_B_CPU1_SB_PAR")
	)
	(segment
		(start 67.103244 -247.118124)
		(end 66.910204 -247.311164)
		(width 0.18288)
		(layer "In2.Cu")
		(net "M_B_CPU1_SB_PAR")
	)
	(segment
		(start 70.633844 -247.201436)
		(end 70.633844 -246.553736)
		(width 0.18288)
		(layer "In2.Cu")
		(net "M_B_CPU1_SB_PAR")
	)
	(segment
		(start 69.028564 -246.363998)
		(end 68.708524 -246.363998)
		(width 0.18288)
		(layer "In2.Cu")
		(net "M_B_CPU1_SB_PAR")
	)
	(segment
		(start 67.809364 -247.201436)
		(end 67.809364 -246.553736)
		(width 0.18288)
		(layer "In2.Cu")
		(net "M_B_CPU1_SB_PAR")
	)
	(segment
		(start 63.794386 -247.036082)
		(end 63.178182 -246.419878)
		(width 0.18288)
		(layer "In2.Cu")
		(net "M_B_CPU1_SB_PAR")
	)
	(segment
		(start 70.633844 -246.553736)
		(end 70.440804 -246.360696)
		(width 0.18288)
		(layer "In2.Cu")
		(net "M_B_CPU1_SB_PAR")
	)
	(segment
		(start 67.809364 -246.553736)
		(end 67.616324 -246.360696)
		(width 0.18288)
		(layer "In2.Cu")
		(net "M_B_CPU1_SB_PAR")
	)
	(segment
		(start 59.201812 -247.217946)
		(end 58.87339 -246.889524)
		(width 0.18288)
		(layer "In2.Cu")
		(net "M_B_CPU1_SB_PAR")
	)
	(segment
		(start 55.079392 -247.053862)
		(end 54.330092 -247.053862)
		(width 0.18288)
		(layer "In2.Cu")
		(net "M_B_CPU1_SB_PAR")
	)
	(segment
		(start 74.200258 -246.565166)
		(end 73.364344 -247.40108)
		(width 0.18288)
		(layer "In2.Cu")
		(net "M_B_CPU1_SB_PAR")
	)
	(segment
		(start 83.709764 -246.73941)
		(end 83.53552 -246.565166)
		(width 0.088646)
		(layer "In2.Cu")
		(net "M_B_CPU1_SB_PAR")
	)
	(segment
		(start 54.330092 -247.053862)
		(end 53.937154 -246.660924)
		(width 0.18288)
		(layer "In2.Cu")
		(net "M_B_CPU1_SB_PAR")
	)
	(segment
		(start 52.892198 -246.660924)
		(end 52.49926 -247.053862)
		(width 0.18288)
		(layer "In2.Cu")
		(net "M_B_CPU1_SB_PAR")
	)
	(segment
		(start 73.364344 -247.40108)
		(end 70.833488 -247.40108)
		(width 0.18288)
		(layer "In2.Cu")
		(net "M_B_CPU1_SB_PAR")
	)
	(segment
		(start 58.492898 -246.889524)
		(end 57.999884 -247.382538)
		(width 0.18288)
		(layer "In2.Cu")
		(net "M_B_CPU1_SB_PAR")
	)
	(segment
		(start 56.305958 -246.759476)
		(end 55.373778 -246.759476)
		(width 0.18288)
		(layer "In2.Cu")
		(net "M_B_CPU1_SB_PAR")
	)
	(segment
		(start 52.49926 -247.053862)
		(end 52.12969 -247.053862)
		(width 0.18288)
		(layer "In2.Cu")
		(net "M_B_CPU1_SB_PAR")
	)
	(segment
		(start 58.87339 -246.889524)
		(end 58.492898 -246.889524)
		(width 0.18288)
		(layer "In2.Cu")
		(net "M_B_CPU1_SB_PAR")
	)
	(segment
		(start 52.12969 -247.053862)
		(end 51.692556 -246.616728)
		(width 0.18288)
		(layer "In2.Cu")
		(net "M_B_CPU1_SB_PAR")
	)
	(segment
		(start 88.427814 -246.688864)
		(end 88.4174 -246.682768)
		(width 0.088646)
		(layer "In2.Cu")
		(net "M_B_CPU1_SB_PAR")
	)
	(segment
		(start 68.322444 -247.40108)
		(end 68.009008 -247.40108)
		(width 0.18288)
		(layer "In2.Cu")
		(net "M_B_CPU1_SB_PAR")
	)
	(segment
		(start 70.440804 -246.360696)
		(end 70.120764 -246.360696)
		(width 0.18288)
		(layer "In2.Cu")
		(net "M_B_CPU1_SB_PAR")
	)
	(segment
		(start 69.927724 -247.20804)
		(end 69.734684 -247.40108)
		(width 0.18288)
		(layer "In2.Cu")
		(net "M_B_CPU1_SB_PAR")
	)
	(segment
		(start 59.86399 -247.217946)
		(end 59.201812 -247.217946)
		(width 0.18288)
		(layer "In2.Cu")
		(net "M_B_CPU1_SB_PAR")
	)
	(segment
		(start 55.373778 -246.759476)
		(end 55.079392 -247.053862)
		(width 0.18288)
		(layer "In2.Cu")
		(net "M_B_CPU1_SB_PAR")
	)
	(segment
		(start 83.916266 -246.73941)
		(end 83.709764 -246.73941)
		(width 0.088646)
		(layer "In2.Cu")
		(net "M_B_CPU1_SB_PAR")
	)
	(segment
		(start 63.178182 -246.419878)
		(end 62.904878 -246.419878)
		(width 0.18288)
		(layer "In2.Cu")
		(net "M_B_CPU1_SB_PAR")
	)
	(segment
		(start 51.692556 -246.616728)
		(end 51.064414 -246.616728)
		(width 0.18288)
		(layer "In2.Cu")
		(net "M_B_CPU1_SB_PAR")
	)
	(segment
		(start 67.296284 -246.360696)
		(end 67.103244 -246.553736)
		(width 0.18288)
		(layer "In2.Cu")
		(net "M_B_CPU1_SB_PAR")
	)
	(segment
		(start 61.935106 -247.1166)
		(end 61.87059 -247.052084)
		(width 0.18288)
		(layer "In2.Cu")
		(net "M_B_CPU1_SB_PAR")
	)
	(segment
		(start 61.87059 -247.052084)
		(end 60.029852 -247.052084)
		(width 0.18288)
		(layer "In2.Cu")
		(net "M_B_CPU1_SB_PAR")
	)
	(segment
		(start 83.53552 -246.565166)
		(end 83.14055 -246.565166)
		(width 0.088646)
		(layer "In2.Cu")
		(net "M_B_CPU1_SB_PAR")
	)
	(segment
		(start 68.708524 -246.363998)
		(end 68.515484 -246.557038)
		(width 0.18288)
		(layer "In2.Cu")
		(net "M_B_CPU1_SB_PAR")
	)
	(segment
		(start 53.937154 -246.660924)
		(end 52.892198 -246.660924)
		(width 0.18288)
		(layer "In2.Cu")
		(net "M_B_CPU1_SB_PAR")
	)
	(segment
		(start 68.515484 -246.557038)
		(end 68.515484 -247.20804)
		(width 0.18288)
		(layer "In2.Cu")
		(net "M_B_CPU1_SB_PAR")
	)
	(segment
		(start 70.833488 -247.40108)
		(end 70.633844 -247.201436)
		(width 0.18288)
		(layer "In2.Cu")
		(net "M_B_CPU1_SB_PAR")
	)
	(segment
		(start 68.515484 -247.20804)
		(end 68.322444 -247.40108)
		(width 0.18288)
		(layer "In2.Cu")
		(net "M_B_CPU1_SB_PAR")
	)
	(segment
		(start 57.999884 -247.382538)
		(end 56.92902 -247.382538)
		(width 0.18288)
		(layer "In2.Cu")
		(net "M_B_CPU1_SB_PAR")
	)
	(segment
		(start 69.927724 -246.553736)
		(end 69.927724 -247.20804)
		(width 0.18288)
		(layer "In2.Cu")
		(net "M_B_CPU1_SB_PAR")
	)
	(segment
		(start 67.103244 -246.553736)
		(end 67.103244 -247.118124)
		(width 0.18288)
		(layer "In2.Cu")
		(net "M_B_CPU1_SB_PAR")
	)
	(segment
		(start 62.208156 -247.1166)
		(end 61.935106 -247.1166)
		(width 0.18288)
		(layer "In2.Cu")
		(net "M_B_CPU1_SB_PAR")
	)
	(segment
		(start 69.221604 -246.557038)
		(end 69.028564 -246.363998)
		(width 0.18288)
		(layer "In2.Cu")
		(net "M_B_CPU1_SB_PAR")
	)
	(segment
		(start 90.336624 -246.705628)
		(end 90.307414 -246.688864)
		(width 0.088646)
		(layer "In2.Cu")
		(net "M_B_CPU1_SB_PAR")
	)
	(segment
		(start 66.910204 -247.311164)
		(end 66.637154 -247.311164)
		(width 0.18288)
		(layer "In2.Cu")
		(net "M_B_CPU1_SB_PAR")
	)
	(segment
		(start 69.734684 -247.40108)
		(end 69.421248 -247.40108)
		(width 0.18288)
		(layer "In2.Cu")
		(net "M_B_CPU1_SB_PAR")
	)
	(segment
		(start 67.616324 -246.360696)
		(end 67.296284 -246.360696)
		(width 0.18288)
		(layer "In2.Cu")
		(net "M_B_CPU1_SB_PAR")
	)
	(segment
		(start 66.637154 -247.311164)
		(end 66.362072 -247.036082)
		(width 0.18288)
		(layer "In2.Cu")
		(net "M_B_CPU1_SB_PAR")
	)
	(segment
		(start 90.964766 -247.178322)
		(end 90.336624 -246.705628)
		(width 0.088646)
		(layer "In2.Cu")
		(net "M_B_CPU1_SB_PAR")
	)
	(segment
		(start 69.421248 -247.40108)
		(end 69.221604 -247.201436)
		(width 0.18288)
		(layer "In2.Cu")
		(net "M_B_CPU1_SB_PAR")
	)
	(segment
		(start 89.367614 -246.688864)
		(end 89.352882 -246.680228)
		(width 0.088646)
		(layer "In2.Cu")
		(net "M_B_CPU1_SB_PAR")
	)
	(segment
		(start 68.009008 -247.40108)
		(end 67.809364 -247.201436)
		(width 0.18288)
		(layer "In2.Cu")
		(net "M_B_CPU1_SB_PAR")
	)
	(segment
		(start 66.362072 -247.036082)
		(end 63.794386 -247.036082)
		(width 0.18288)
		(layer "In2.Cu")
		(net "M_B_CPU1_SB_PAR")
	)
	(segment
		(start 69.221604 -247.201436)
		(end 69.221604 -246.557038)
		(width 0.18288)
		(layer "In2.Cu")
		(net "M_B_CPU1_SB_PAR")
	)
	(arc
		(start 84.668868 -246.688864)
		(mid 84.386166 -246.613088)
		(end 84.103464 -246.688864)
		(width 0.088646)
		(layer "In2.Cu")
		(net "M_B_CPU1_SB_PAR")
	)
	(arc
		(start 89.352882 -246.680228)
		(mid 89.076407 -246.612908)
		(end 88.80221 -246.688864)
		(width 0.088646)
		(layer "In2.Cu")
		(net "M_B_CPU1_SB_PAR")
	)
	(arc
		(start 88.4174 -246.682768)
		(mid 88.139222 -246.613045)
		(end 87.862664 -246.688864)
		(width 0.088646)
		(layer "In2.Cu")
		(net "M_B_CPU1_SB_PAR")
	)
	(arc
		(start 87.488268 -246.688864)
		(mid 87.205566 -246.613088)
		(end 86.922864 -246.688864)
		(width 0.088646)
		(layer "In2.Cu")
		(net "M_B_CPU1_SB_PAR")
	)
	(arc
		(start 90.307414 -246.688864)
		(mid 90.024712 -246.613122)
		(end 89.74201 -246.688864)
		(width 0.088646)
		(layer "In2.Cu")
		(net "M_B_CPU1_SB_PAR")
	)
	(arc
		(start 86.922864 -246.688864)
		(mid 86.735666 -246.739007)
		(end 86.548468 -246.688864)
		(width 0.088646)
		(layer "In2.Cu")
		(net "M_B_CPU1_SB_PAR")
	)
	(arc
		(start 87.862664 -246.688864)
		(mid 87.675466 -246.739007)
		(end 87.488268 -246.688864)
		(width 0.088646)
		(layer "In2.Cu")
		(net "M_B_CPU1_SB_PAR")
	)
	(arc
		(start 86.548468 -246.688864)
		(mid 86.265766 -246.613088)
		(end 85.983064 -246.688864)
		(width 0.088646)
		(layer "In2.Cu")
		(net "M_B_CPU1_SB_PAR")
	)
	(arc
		(start 85.983064 -246.688864)
		(mid 85.795866 -246.739007)
		(end 85.608668 -246.688864)
		(width 0.088646)
		(layer "In2.Cu")
		(net "M_B_CPU1_SB_PAR")
	)
	(arc
		(start 88.80221 -246.688864)
		(mid 88.615012 -246.739007)
		(end 88.427814 -246.688864)
		(width 0.088646)
		(layer "In2.Cu")
		(net "M_B_CPU1_SB_PAR")
	)
	(arc
		(start 85.043264 -246.688864)
		(mid 84.856066 -246.739007)
		(end 84.668868 -246.688864)
		(width 0.088646)
		(layer "In2.Cu")
		(net "M_B_CPU1_SB_PAR")
	)
	(arc
		(start 84.103464 -246.688864)
		(mid 84.013192 -246.726463)
		(end 83.916266 -246.73941)
		(width 0.088646)
		(layer "In2.Cu")
		(net "M_B_CPU1_SB_PAR")
	)
	(arc
		(start 85.608668 -246.688864)
		(mid 85.325966 -246.613088)
		(end 85.043264 -246.688864)
		(width 0.088646)
		(layer "In2.Cu")
		(net "M_B_CPU1_SB_PAR")
	)
	(arc
		(start 89.74201 -246.688864)
		(mid 89.554812 -246.739007)
		(end 89.367614 -246.688864)
		(width 0.088646)
		(layer "In2.Cu")
		(net "M_B_CPU1_SB_PAR")
	)
	(segment
		(start 41.293288 -238.549434)
		(end 41.291764 -238.549434)
		(width 0.101854)
		(layer "F.Cu")
		(net "M_B_CPU1_SB_DQS_DP<9>")
	)
	(segment
		(start 43.768772 -238.541814)
		(end 43.61688 -238.541814)
		(width 0.20066)
		(layer "F.Cu")
		(net "M_B_CPU1_SB_DQS_DP<9>")
	)
	(segment
		(start 46.964346 -238.116618)
		(end 45.859446 -238.116618)
		(width 0.20066)
		(layer "F.Cu")
		(net "M_B_CPU1_SB_DQS_DP<9>")
	)
	(segment
		(start 45.310806 -238.116618)
		(end 45.049694 -237.855506)
		(width 0.20066)
		(layer "F.Cu")
		(net "M_B_CPU1_SB_DQS_DP<9>")
	)
	(segment
		(start 38.853618 -238.116618)
		(end 38.315646 -238.116618)
		(width 0.20066)
		(layer "F.Cu")
		(net "M_B_CPU1_SB_DQS_DP<9>")
	)
	(segment
		(start 41.071546 -238.549434)
		(end 40.802814 -238.280702)
		(width 0.20066)
		(layer "F.Cu")
		(net "M_B_CPU1_SB_DQS_DP<9>")
	)
	(segment
		(start 45.859446 -238.116618)
		(end 45.310806 -238.116618)
		(width 0.20066)
		(layer "F.Cu")
		(net "M_B_CPU1_SB_DQS_DP<9>")
	)
	(segment
		(start 44.355766 -238.280702)
		(end 44.029884 -238.280702)
		(width 0.20066)
		(layer "F.Cu")
		(net "M_B_CPU1_SB_DQS_DP<9>")
	)
	(segment
		(start 88.145366 -242.295172)
		(end 88.14562 -242.294918)
		(width 0.20066)
		(layer "F.Cu")
		(net "M_B_CPU1_SB_DQS_DP<9>")
	)
	(segment
		(start 43.293284 -238.541814)
		(end 41.53789 -238.541814)
		(width 0.1016)
		(layer "F.Cu")
		(net "M_B_CPU1_SB_DQS_DP<9>")
	)
	(segment
		(start 41.300908 -238.541814)
		(end 41.293288 -238.549434)
		(width 0.101854)
		(layer "F.Cu")
		(net "M_B_CPU1_SB_DQS_DP<9>")
	)
	(segment
		(start 41.53789 -238.541814)
		(end 41.300908 -238.541814)
		(width 0.101854)
		(layer "F.Cu")
		(net "M_B_CPU1_SB_DQS_DP<9>")
	)
	(segment
		(start 40.175688 -238.280702)
		(end 39.539672 -237.855506)
		(width 0.20066)
		(layer "F.Cu")
		(net "M_B_CPU1_SB_DQS_DP<9>")
	)
	(segment
		(start 44.029884 -238.280702)
		(end 43.768772 -238.541814)
		(width 0.20066)
		(layer "F.Cu")
		(net "M_B_CPU1_SB_DQS_DP<9>")
	)
	(segment
		(start 39.539672 -237.855506)
		(end 39.11473 -237.855506)
		(width 0.20066)
		(layer "F.Cu")
		(net "M_B_CPU1_SB_DQS_DP<9>")
	)
	(segment
		(start 45.049694 -237.855506)
		(end 44.780962 -237.855506)
		(width 0.20066)
		(layer "F.Cu")
		(net "M_B_CPU1_SB_DQS_DP<9>")
	)
	(segment
		(start 39.11473 -237.855506)
		(end 38.853618 -238.116618)
		(width 0.20066)
		(layer "F.Cu")
		(net "M_B_CPU1_SB_DQS_DP<9>")
	)
	(segment
		(start 44.780962 -237.855506)
		(end 44.355766 -238.280702)
		(width 0.20066)
		(layer "F.Cu")
		(net "M_B_CPU1_SB_DQS_DP<9>")
	)
	(segment
		(start 41.291764 -238.549434)
		(end 41.071546 -238.549434)
		(width 0.20066)
		(layer "F.Cu")
		(net "M_B_CPU1_SB_DQS_DP<9>")
	)
	(segment
		(start 43.61688 -238.541814)
		(end 43.293284 -238.541814)
		(width 0.101854)
		(layer "F.Cu")
		(net "M_B_CPU1_SB_DQS_DP<9>")
	)
	(segment
		(start 88.145366 -242.830858)
		(end 88.145366 -242.295172)
		(width 0.20066)
		(layer "F.Cu")
		(net "M_B_CPU1_SB_DQS_DP<9>")
	)
	(segment
		(start 40.802814 -238.280702)
		(end 40.175688 -238.280702)
		(width 0.20066)
		(layer "F.Cu")
		(net "M_B_CPU1_SB_DQS_DP<9>")
	)
	(segment
		(start 74.413364 -241.224054)
		(end 74.025506 -240.836196)
		(width 0.18288)
		(layer "In2.Cu")
		(net "M_B_CPU1_SB_DQS_DP<9>")
	)
	(segment
		(start 51.252882 -235.991654)
		(end 50.864262 -235.991654)
		(width 0.18288)
		(layer "In2.Cu")
		(net "M_B_CPU1_SB_DQS_DP<9>")
	)
	(segment
		(start 59.653932 -236.847126)
		(end 59.350656 -236.54385)
		(width 0.18288)
		(layer "In2.Cu")
		(net "M_B_CPU1_SB_DQS_DP<9>")
	)
	(segment
		(start 68.18249 -237.272576)
		(end 68.11518 -237.109762)
		(width 0.18288)
		(layer "In2.Cu")
		(net "M_B_CPU1_SB_DQS_DP<9>")
	)
	(segment
		(start 58.744612 -236.54385)
		(end 58.50128 -236.300518)
		(width 0.18288)
		(layer "In2.Cu")
		(net "M_B_CPU1_SB_DQS_DP<9>")
	)
	(segment
		(start 56.622442 -236.144308)
		(end 56.622442 -236.160564)
		(width 0.16002)
		(layer "In2.Cu")
		(net "M_B_CPU1_SB_DQS_DP<9>")
	)
	(segment
		(start 54.05501 -235.104432)
		(end 52.751482 -235.104432)
		(width 0.18288)
		(layer "In2.Cu")
		(net "M_B_CPU1_SB_DQS_DP<9>")
	)
	(segment
		(start 68.11518 -237.109762)
		(end 67.069716 -236.676438)
		(width 0.18288)
		(layer "In2.Cu")
		(net "M_B_CPU1_SB_DQS_DP<9>")
	)
	(segment
		(start 67.069716 -236.676438)
		(end 66.621914 -236.51845)
		(width 0.18288)
		(layer "In2.Cu")
		(net "M_B_CPU1_SB_DQS_DP<9>")
	)
	(segment
		(start 70.669658 -238.303816)
		(end 70.602348 -238.141002)
		(width 0.18288)
		(layer "In2.Cu")
		(net "M_B_CPU1_SB_DQS_DP<9>")
	)
	(segment
		(start 69.933058 -237.998254)
		(end 69.426074 -237.788196)
		(width 0.18288)
		(layer "In2.Cu")
		(net "M_B_CPU1_SB_DQS_DP<9>")
	)
	(segment
		(start 73.073514 -239.884204)
		(end 72.897492 -239.884204)
		(width 0.18288)
		(layer "In2.Cu")
		(net "M_B_CPU1_SB_DQS_DP<9>")
	)
	(segment
		(start 71.176642 -238.513874)
		(end 70.669658 -238.303816)
		(width 0.18288)
		(layer "In2.Cu")
		(net "M_B_CPU1_SB_DQS_DP<9>")
	)
	(segment
		(start 56.838342 -235.944664)
		(end 56.822086 -235.944664)
		(width 0.16002)
		(layer "In2.Cu")
		(net "M_B_CPU1_SB_DQS_DP<9>")
	)
	(segment
		(start 62.079632 -236.847126)
		(end 61.77534 -236.542834)
		(width 0.18288)
		(layer "In2.Cu")
		(net "M_B_CPU1_SB_DQS_DP<9>")
	)
	(segment
		(start 54.157118 -235.20654)
		(end 54.128924 -235.178346)
		(width 0.16002)
		(layer "In2.Cu")
		(net "M_B_CPU1_SB_DQS_DP<9>")
	)
	(segment
		(start 68.852034 -237.415324)
		(end 68.689474 -237.482634)
		(width 0.18288)
		(layer "In2.Cu")
		(net "M_B_CPU1_SB_DQS_DP<9>")
	)
	(segment
		(start 54.401212 -235.450634)
		(end 54.373018 -235.42244)
		(width 0.16002)
		(layer "In2.Cu")
		(net "M_B_CPU1_SB_DQS_DP<9>")
	)
	(segment
		(start 84.152486 -241.920014)
		(end 83.956144 -242.116356)
		(width 0.088646)
		(layer "In2.Cu")
		(net "M_B_CPU1_SB_DQS_DP<9>")
	)
	(segment
		(start 64.293242 -236.056424)
		(end 64.276986 -236.056424)
		(width 0.16002)
		(layer "In2.Cu")
		(net "M_B_CPU1_SB_DQS_DP<9>")
	)
	(segment
		(start 56.622442 -236.160564)
		(end 56.594248 -236.188758)
		(width 0.16002)
		(layer "In2.Cu")
		(net "M_B_CPU1_SB_DQS_DP<9>")
	)
	(segment
		(start 52.433474 -235.406184)
		(end 52.433474 -235.42244)
		(width 0.16002)
		(layer "In2.Cu")
		(net "M_B_CPU1_SB_DQS_DP<9>")
	)
	(segment
		(start 47.748698 -237.808516)
		(end 47.1678 -237.808516)
		(width 0.18288)
		(layer "In2.Cu")
		(net "M_B_CPU1_SB_DQS_DP<9>")
	)
	(segment
		(start 63.806832 -236.542834)
		(end 62.75578 -236.542834)
		(width 0.18288)
		(layer "In2.Cu")
		(net "M_B_CPU1_SB_DQS_DP<9>")
	)
	(segment
		(start 57.997852 -235.79709)
		(end 56.985916 -235.79709)
		(width 0.18288)
		(layer "In2.Cu")
		(net "M_B_CPU1_SB_DQS_DP<9>")
	)
	(segment
		(start 88.128094 -242.231164)
		(end 87.945468 -242.090702)
		(width 0.088646)
		(layer "In2.Cu")
		(net "M_B_CPU1_SB_DQS_DP<9>")
	)
	(segment
		(start 60.33008 -236.542834)
		(end 60.025788 -236.847126)
		(width 0.18288)
		(layer "In2.Cu")
		(net "M_B_CPU1_SB_DQS_DP<9>")
	)
	(segment
		(start 59.350656 -236.54385)
		(end 58.744612 -236.54385)
		(width 0.18288)
		(layer "In2.Cu")
		(net "M_B_CPU1_SB_DQS_DP<9>")
	)
	(segment
		(start 50.591466 -235.718858)
		(end 49.527968 -235.718858)
		(width 0.18288)
		(layer "In2.Cu")
		(net "M_B_CPU1_SB_DQS_DP<9>")
	)
	(segment
		(start 69.358764 -237.625382)
		(end 68.852034 -237.415324)
		(width 0.18288)
		(layer "In2.Cu")
		(net "M_B_CPU1_SB_DQS_DP<9>")
	)
	(segment
		(start 87.422736 -241.988086)
		(end 87.39251 -241.97056)
		(width 0.088646)
		(layer "In2.Cu")
		(net "M_B_CPU1_SB_DQS_DP<9>")
	)
	(segment
		(start 72.897492 -239.884204)
		(end 72.50938 -239.496092)
		(width 0.18288)
		(layer "In2.Cu")
		(net "M_B_CPU1_SB_DQS_DP<9>")
	)
	(segment
		(start 64.412622 -235.937044)
		(end 64.321436 -236.02823)
		(width 0.18288)
		(layer "In2.Cu")
		(net "M_B_CPU1_SB_DQS_DP<9>")
	)
	(segment
		(start 74.801476 -241.788188)
		(end 74.413364 -241.400076)
		(width 0.18288)
		(layer "In2.Cu")
		(net "M_B_CPU1_SB_DQS_DP<9>")
	)
	(segment
		(start 58.50128 -236.300518)
		(end 58.473086 -236.272324)
		(width 0.16002)
		(layer "In2.Cu")
		(net "M_B_CPU1_SB_DQS_DP<9>")
	)
	(segment
		(start 61.77534 -236.542834)
		(end 60.33008 -236.542834)
		(width 0.18288)
		(layer "In2.Cu")
		(net "M_B_CPU1_SB_DQS_DP<9>")
	)
	(segment
		(start 52.751482 -235.104432)
		(end 52.677568 -235.178346)
		(width 0.18288)
		(layer "In2.Cu")
		(net "M_B_CPU1_SB_DQS_DP<9>")
	)
	(segment
		(start 48.907192 -236.650022)
		(end 48.580294 -236.97692)
		(width 0.18288)
		(layer "In2.Cu")
		(net "M_B_CPU1_SB_DQS_DP<9>")
	)
	(segment
		(start 64.321436 -236.02823)
		(end 64.293242 -236.056424)
		(width 0.16002)
		(layer "In2.Cu")
		(net "M_B_CPU1_SB_DQS_DP<9>")
	)
	(segment
		(start 48.01616 -237.541054)
		(end 47.748698 -237.808516)
		(width 0.18288)
		(layer "In2.Cu")
		(net "M_B_CPU1_SB_DQS_DP<9>")
	)
	(segment
		(start 48.580294 -236.97692)
		(end 48.580294 -237.152942)
		(width 0.18288)
		(layer "In2.Cu")
		(net "M_B_CPU1_SB_DQS_DP<9>")
	)
	(segment
		(start 48.580294 -237.152942)
		(end 48.192182 -237.541054)
		(width 0.18288)
		(layer "In2.Cu")
		(net "M_B_CPU1_SB_DQS_DP<9>")
	)
	(segment
		(start 49.086008 -236.160818)
		(end 48.907192 -236.339634)
		(width 0.18288)
		(layer "In2.Cu")
		(net "M_B_CPU1_SB_DQS_DP<9>")
	)
	(segment
		(start 71.845932 -238.656622)
		(end 71.339202 -238.446564)
		(width 0.18288)
		(layer "In2.Cu")
		(net "M_B_CPU1_SB_DQS_DP<9>")
	)
	(segment
		(start 87.443818 -242.005358)
		(end 87.422736 -241.988086)
		(width 0.088646)
		(layer "In2.Cu")
		(net "M_B_CPU1_SB_DQS_DP<9>")
	)
	(segment
		(start 87.945468 -242.090702)
		(end 87.681816 -242.090702)
		(width 0.088646)
		(layer "In2.Cu")
		(net "M_B_CPU1_SB_DQS_DP<9>")
	)
	(segment
		(start 49.114202 -236.116368)
		(end 49.114202 -236.132624)
		(width 0.16002)
		(layer "In2.Cu")
		(net "M_B_CPU1_SB_DQS_DP<9>")
	)
	(segment
		(start 56.822086 -235.944664)
		(end 56.622442 -236.144308)
		(width 0.16002)
		(layer "In2.Cu")
		(net "M_B_CPU1_SB_DQS_DP<9>")
	)
	(segment
		(start 69.426074 -237.788196)
		(end 69.358764 -237.625382)
		(width 0.18288)
		(layer "In2.Cu")
		(net "M_B_CPU1_SB_DQS_DP<9>")
	)
	(segment
		(start 47.1678 -237.808516)
		(end 46.964346 -238.01197)
		(width 0.18288)
		(layer "In2.Cu")
		(net "M_B_CPU1_SB_DQS_DP<9>")
	)
	(segment
		(start 58.273442 -236.056424)
		(end 58.257186 -236.056424)
		(width 0.16002)
		(layer "In2.Cu")
		(net "M_B_CPU1_SB_DQS_DP<9>")
	)
	(segment
		(start 64.077342 -236.256068)
		(end 64.077342 -236.272324)
		(width 0.16002)
		(layer "In2.Cu")
		(net "M_B_CPU1_SB_DQS_DP<9>")
	)
	(segment
		(start 65.986406 -236.241844)
		(end 65.986406 -236.225588)
		(width 0.16002)
		(layer "In2.Cu")
		(net "M_B_CPU1_SB_DQS_DP<9>")
	)
	(segment
		(start 54.373018 -235.42244)
		(end 54.373018 -235.406184)
		(width 0.16002)
		(layer "In2.Cu")
		(net "M_B_CPU1_SB_DQS_DP<9>")
	)
	(segment
		(start 65.681606 -235.937044)
		(end 64.412622 -235.937044)
		(width 0.18288)
		(layer "In2.Cu")
		(net "M_B_CPU1_SB_DQS_DP<9>")
	)
	(segment
		(start 58.473086 -236.256068)
		(end 58.273442 -236.056424)
		(width 0.16002)
		(layer "In2.Cu")
		(net "M_B_CPU1_SB_DQS_DP<9>")
	)
	(segment
		(start 73.461372 -240.448084)
		(end 73.461372 -240.272062)
		(width 0.18288)
		(layer "In2.Cu")
		(net "M_B_CPU1_SB_DQS_DP<9>")
	)
	(segment
		(start 52.677568 -235.178346)
		(end 52.649374 -235.20654)
		(width 0.16002)
		(layer "In2.Cu")
		(net "M_B_CPU1_SB_DQS_DP<9>")
	)
	(segment
		(start 56.411876 -236.37113)
		(end 55.92064 -236.37113)
		(width 0.18288)
		(layer "In2.Cu")
		(net "M_B_CPU1_SB_DQS_DP<9>")
	)
	(segment
		(start 71.339202 -238.446564)
		(end 71.176642 -238.513874)
		(width 0.18288)
		(layer "In2.Cu")
		(net "M_B_CPU1_SB_DQS_DP<9>")
	)
	(segment
		(start 49.527968 -235.718858)
		(end 49.358296 -235.88853)
		(width 0.18288)
		(layer "In2.Cu")
		(net "M_B_CPU1_SB_DQS_DP<9>")
	)
	(segment
		(start 49.313846 -235.916724)
		(end 49.114202 -236.116368)
		(width 0.16002)
		(layer "In2.Cu")
		(net "M_B_CPU1_SB_DQS_DP<9>")
	)
	(segment
		(start 70.095618 -237.930944)
		(end 69.933058 -237.998254)
		(width 0.18288)
		(layer "In2.Cu")
		(net "M_B_CPU1_SB_DQS_DP<9>")
	)
	(segment
		(start 48.192182 -237.541054)
		(end 48.01616 -237.541054)
		(width 0.18288)
		(layer "In2.Cu")
		(net "M_B_CPU1_SB_DQS_DP<9>")
	)
	(segment
		(start 88.14562 -242.294918)
		(end 88.128094 -242.231164)
		(width 0.088646)
		(layer "In2.Cu")
		(net "M_B_CPU1_SB_DQS_DP<9>")
	)
	(segment
		(start 85.138514 -241.97056)
		(end 85.1281 -241.976656)
		(width 0.088646)
		(layer "In2.Cu")
		(net "M_B_CPU1_SB_DQS_DP<9>")
	)
	(segment
		(start 83.123786 -242.116356)
		(end 83.064096 -242.176046)
		(width 0.088646)
		(layer "In2.Cu")
		(net "M_B_CPU1_SB_DQS_DP<9>")
	)
	(segment
		(start 62.75578 -236.542834)
		(end 62.451488 -236.847126)
		(width 0.18288)
		(layer "In2.Cu")
		(net "M_B_CPU1_SB_DQS_DP<9>")
	)
	(segment
		(start 50.864262 -235.991654)
		(end 50.591466 -235.718858)
		(width 0.18288)
		(layer "In2.Cu")
		(net "M_B_CPU1_SB_DQS_DP<9>")
	)
	(segment
		(start 84.385912 -241.920014)
		(end 84.152486 -241.920014)
		(width 0.088646)
		(layer "In2.Cu")
		(net "M_B_CPU1_SB_DQS_DP<9>")
	)
	(segment
		(start 56.594248 -236.188758)
		(end 56.411876 -236.37113)
		(width 0.18288)
		(layer "In2.Cu")
		(net "M_B_CPU1_SB_DQS_DP<9>")
	)
	(segment
		(start 64.049148 -236.300518)
		(end 63.806832 -236.542834)
		(width 0.18288)
		(layer "In2.Cu")
		(net "M_B_CPU1_SB_DQS_DP<9>")
	)
	(segment
		(start 64.077342 -236.272324)
		(end 64.049148 -236.300518)
		(width 0.16002)
		(layer "In2.Cu")
		(net "M_B_CPU1_SB_DQS_DP<9>")
	)
	(segment
		(start 56.866536 -235.91647)
		(end 56.838342 -235.944664)
		(width 0.16002)
		(layer "In2.Cu")
		(net "M_B_CPU1_SB_DQS_DP<9>")
	)
	(segment
		(start 54.373018 -235.406184)
		(end 54.173374 -235.20654)
		(width 0.16002)
		(layer "In2.Cu")
		(net "M_B_CPU1_SB_DQS_DP<9>")
	)
	(segment
		(start 72.50938 -239.496092)
		(end 72.50938 -239.32007)
		(width 0.18288)
		(layer "In2.Cu")
		(net "M_B_CPU1_SB_DQS_DP<9>")
	)
	(segment
		(start 73.461372 -240.272062)
		(end 73.073514 -239.884204)
		(width 0.18288)
		(layer "In2.Cu")
		(net "M_B_CPU1_SB_DQS_DP<9>")
	)
	(segment
		(start 49.330102 -235.916724)
		(end 49.313846 -235.916724)
		(width 0.16002)
		(layer "In2.Cu")
		(net "M_B_CPU1_SB_DQS_DP<9>")
	)
	(segment
		(start 49.114202 -236.132624)
		(end 49.086008 -236.160818)
		(width 0.16002)
		(layer "In2.Cu")
		(net "M_B_CPU1_SB_DQS_DP<9>")
	)
	(segment
		(start 87.018114 -241.97056)
		(end 87.0077 -241.976656)
		(width 0.088646)
		(layer "In2.Cu")
		(net "M_B_CPU1_SB_DQS_DP<9>")
	)
	(segment
		(start 52.433474 -235.42244)
		(end 52.40528 -235.450634)
		(width 0.16002)
		(layer "In2.Cu")
		(net "M_B_CPU1_SB_DQS_DP<9>")
	)
	(segment
		(start 62.451488 -236.847126)
		(end 62.079632 -236.847126)
		(width 0.18288)
		(layer "In2.Cu")
		(net "M_B_CPU1_SB_DQS_DP<9>")
	)
	(segment
		(start 64.276986 -236.056424)
		(end 64.077342 -236.256068)
		(width 0.16002)
		(layer "In2.Cu")
		(net "M_B_CPU1_SB_DQS_DP<9>")
	)
	(segment
		(start 72.50938 -239.32007)
		(end 71.845932 -238.656622)
		(width 0.18288)
		(layer "In2.Cu")
		(net "M_B_CPU1_SB_DQS_DP<9>")
	)
	(segment
		(start 65.770506 -236.025944)
		(end 65.742312 -235.99775)
		(width 0.16002)
		(layer "In2.Cu")
		(net "M_B_CPU1_SB_DQS_DP<9>")
	)
	(segment
		(start 55.92064 -236.37113)
		(end 54.898036 -235.947458)
		(width 0.18288)
		(layer "In2.Cu")
		(net "M_B_CPU1_SB_DQS_DP<9>")
	)
	(segment
		(start 46.964346 -238.01197)
		(end 46.964346 -238.116618)
		(width 0.18288)
		(layer "In2.Cu")
		(net "M_B_CPU1_SB_DQS_DP<9>")
	)
	(segment
		(start 65.786762 -236.025944)
		(end 65.770506 -236.025944)
		(width 0.16002)
		(layer "In2.Cu")
		(net "M_B_CPU1_SB_DQS_DP<9>")
	)
	(segment
		(start 66.263012 -236.51845)
		(end 66.0146 -236.270038)
		(width 0.18288)
		(layer "In2.Cu")
		(net "M_B_CPU1_SB_DQS_DP<9>")
	)
	(segment
		(start 65.986406 -236.225588)
		(end 65.786762 -236.025944)
		(width 0.16002)
		(layer "In2.Cu")
		(net "M_B_CPU1_SB_DQS_DP<9>")
	)
	(segment
		(start 51.51882 -235.725716)
		(end 51.252882 -235.991654)
		(width 0.18288)
		(layer "In2.Cu")
		(net "M_B_CPU1_SB_DQS_DP<9>")
	)
	(segment
		(start 54.173374 -235.20654)
		(end 54.157118 -235.20654)
		(width 0.16002)
		(layer "In2.Cu")
		(net "M_B_CPU1_SB_DQS_DP<9>")
	)
	(segment
		(start 56.985916 -235.79709)
		(end 56.866536 -235.91647)
		(width 0.18288)
		(layer "In2.Cu")
		(net "M_B_CPU1_SB_DQS_DP<9>")
	)
	(segment
		(start 70.602348 -238.141002)
		(end 70.095618 -237.930944)
		(width 0.18288)
		(layer "In2.Cu")
		(net "M_B_CPU1_SB_DQS_DP<9>")
	)
	(segment
		(start 73.849484 -240.836196)
		(end 73.461372 -240.448084)
		(width 0.18288)
		(layer "In2.Cu")
		(net "M_B_CPU1_SB_DQS_DP<9>")
	)
	(segment
		(start 86.078568 -241.97056)
		(end 86.068154 -241.976656)
		(width 0.088646)
		(layer "In2.Cu")
		(net "M_B_CPU1_SB_DQS_DP<9>")
	)
	(segment
		(start 74.413364 -241.400076)
		(end 74.413364 -241.224054)
		(width 0.18288)
		(layer "In2.Cu")
		(net "M_B_CPU1_SB_DQS_DP<9>")
	)
	(segment
		(start 52.40528 -235.450634)
		(end 52.130198 -235.725716)
		(width 0.18288)
		(layer "In2.Cu")
		(net "M_B_CPU1_SB_DQS_DP<9>")
	)
	(segment
		(start 58.473086 -236.272324)
		(end 58.473086 -236.256068)
		(width 0.16002)
		(layer "In2.Cu")
		(net "M_B_CPU1_SB_DQS_DP<9>")
	)
	(segment
		(start 60.025788 -236.847126)
		(end 59.653932 -236.847126)
		(width 0.18288)
		(layer "In2.Cu")
		(net "M_B_CPU1_SB_DQS_DP<9>")
	)
	(segment
		(start 54.128924 -235.178346)
		(end 54.05501 -235.104432)
		(width 0.18288)
		(layer "In2.Cu")
		(net "M_B_CPU1_SB_DQS_DP<9>")
	)
	(segment
		(start 52.633118 -235.20654)
		(end 52.433474 -235.406184)
		(width 0.16002)
		(layer "In2.Cu")
		(net "M_B_CPU1_SB_DQS_DP<9>")
	)
	(segment
		(start 66.0146 -236.270038)
		(end 65.986406 -236.241844)
		(width 0.16002)
		(layer "In2.Cu")
		(net "M_B_CPU1_SB_DQS_DP<9>")
	)
	(segment
		(start 49.358296 -235.88853)
		(end 49.330102 -235.916724)
		(width 0.16002)
		(layer "In2.Cu")
		(net "M_B_CPU1_SB_DQS_DP<9>")
	)
	(segment
		(start 65.742312 -235.99775)
		(end 65.681606 -235.937044)
		(width 0.18288)
		(layer "In2.Cu")
		(net "M_B_CPU1_SB_DQS_DP<9>")
	)
	(segment
		(start 54.898036 -235.947458)
		(end 54.401212 -235.450634)
		(width 0.18288)
		(layer "In2.Cu")
		(net "M_B_CPU1_SB_DQS_DP<9>")
	)
	(segment
		(start 75.365356 -242.176046)
		(end 74.977498 -241.788188)
		(width 0.18288)
		(layer "In2.Cu")
		(net "M_B_CPU1_SB_DQS_DP<9>")
	)
	(segment
		(start 52.130198 -235.725716)
		(end 51.51882 -235.725716)
		(width 0.18288)
		(layer "In2.Cu")
		(net "M_B_CPU1_SB_DQS_DP<9>")
	)
	(segment
		(start 66.621914 -236.51845)
		(end 66.263012 -236.51845)
		(width 0.18288)
		(layer "In2.Cu")
		(net "M_B_CPU1_SB_DQS_DP<9>")
	)
	(segment
		(start 58.257186 -236.056424)
		(end 58.228992 -236.02823)
		(width 0.16002)
		(layer "In2.Cu")
		(net "M_B_CPU1_SB_DQS_DP<9>")
	)
	(segment
		(start 74.025506 -240.836196)
		(end 73.849484 -240.836196)
		(width 0.18288)
		(layer "In2.Cu")
		(net "M_B_CPU1_SB_DQS_DP<9>")
	)
	(segment
		(start 48.907192 -236.339634)
		(end 48.907192 -236.650022)
		(width 0.18288)
		(layer "In2.Cu")
		(net "M_B_CPU1_SB_DQS_DP<9>")
	)
	(segment
		(start 68.689474 -237.482634)
		(end 68.18249 -237.272576)
		(width 0.18288)
		(layer "In2.Cu")
		(net "M_B_CPU1_SB_DQS_DP<9>")
	)
	(segment
		(start 74.977498 -241.788188)
		(end 74.801476 -241.788188)
		(width 0.18288)
		(layer "In2.Cu")
		(net "M_B_CPU1_SB_DQS_DP<9>")
	)
	(segment
		(start 83.956144 -242.116356)
		(end 83.123786 -242.116356)
		(width 0.088646)
		(layer "In2.Cu")
		(net "M_B_CPU1_SB_DQS_DP<9>")
	)
	(segment
		(start 83.064096 -242.176046)
		(end 75.365356 -242.176046)
		(width 0.18288)
		(layer "In2.Cu")
		(net "M_B_CPU1_SB_DQS_DP<9>")
	)
	(segment
		(start 52.649374 -235.20654)
		(end 52.633118 -235.20654)
		(width 0.16002)
		(layer "In2.Cu")
		(net "M_B_CPU1_SB_DQS_DP<9>")
	)
	(segment
		(start 58.228992 -236.02823)
		(end 57.997852 -235.79709)
		(width 0.18288)
		(layer "In2.Cu")
		(net "M_B_CPU1_SB_DQS_DP<9>")
	)
	(arc
		(start 87.681816 -242.090702)
		(mid 87.555425 -242.068664)
		(end 87.443818 -242.005358)
		(width 0.088646)
		(layer "In2.Cu")
		(net "M_B_CPU1_SB_DQS_DP<9>")
	)
	(arc
		(start 85.1281 -241.976656)
		(mid 84.849668 -242.046502)
		(end 84.572856 -241.97056)
		(width 0.088646)
		(layer "In2.Cu")
		(net "M_B_CPU1_SB_DQS_DP<9>")
	)
	(arc
		(start 87.39251 -241.97056)
		(mid 87.205312 -241.920417)
		(end 87.018114 -241.97056)
		(width 0.088646)
		(layer "In2.Cu")
		(net "M_B_CPU1_SB_DQS_DP<9>")
	)
	(arc
		(start 86.452964 -241.97056)
		(mid 86.265766 -241.920417)
		(end 86.078568 -241.97056)
		(width 0.088646)
		(layer "In2.Cu")
		(net "M_B_CPU1_SB_DQS_DP<9>")
	)
	(arc
		(start 85.51291 -241.97056)
		(mid 85.325712 -241.920417)
		(end 85.138514 -241.97056)
		(width 0.088646)
		(layer "In2.Cu")
		(net "M_B_CPU1_SB_DQS_DP<9>")
	)
	(arc
		(start 87.0077 -241.976656)
		(mid 86.729522 -242.046379)
		(end 86.452964 -241.97056)
		(width 0.088646)
		(layer "In2.Cu")
		(net "M_B_CPU1_SB_DQS_DP<9>")
	)
	(arc
		(start 84.572856 -241.97056)
		(mid 84.482707 -241.932994)
		(end 84.385912 -241.920014)
		(width 0.088646)
		(layer "In2.Cu")
		(net "M_B_CPU1_SB_DQS_DP<9>")
	)
	(arc
		(start 86.068154 -241.976656)
		(mid 85.789722 -242.046502)
		(end 85.51291 -241.97056)
		(width 0.088646)
		(layer "In2.Cu")
		(net "M_B_CPU1_SB_DQS_DP<9>")
	)
	(segment
		(start 44.537884 -198.58609)
		(end 44.26839 -198.855584)
		(width 0.20066)
		(layer "F.Cu")
		(net "M_B_CPU1_SB_DQS_DP<8>")
	)
	(segment
		(start 43.485816 -199.277986)
		(end 43.151552 -199.277986)
		(width 0.20066)
		(layer "F.Cu")
		(net "M_B_CPU1_SB_DQS_DP<8>")
	)
	(segment
		(start 44.98213 -198.591678)
		(end 44.74083 -198.591678)
		(width 0.101854)
		(layer "F.Cu")
		(net "M_B_CPU1_SB_DQS_DP<8>")
	)
	(segment
		(start 44.26839 -198.855584)
		(end 43.908218 -198.855584)
		(width 0.20066)
		(layer "F.Cu")
		(net "M_B_CPU1_SB_DQS_DP<8>")
	)
	(segment
		(start 44.74083 -198.591678)
		(end 44.735242 -198.58609)
		(width 0.101854)
		(layer "F.Cu")
		(net "M_B_CPU1_SB_DQS_DP<8>")
	)
	(segment
		(start 42.890186 -199.01662)
		(end 42.415714 -199.01662)
		(width 0.20066)
		(layer "F.Cu")
		(net "M_B_CPU1_SB_DQS_DP<8>")
	)
	(segment
		(start 47.462948 -198.853044)
		(end 47.201836 -198.591932)
		(width 0.20066)
		(layer "F.Cu")
		(net "M_B_CPU1_SB_DQS_DP<8>")
	)
	(segment
		(start 87.675466 -225.739198)
		(end 87.675466 -225.203258)
		(width 0.20066)
		(layer "F.Cu")
		(net "M_B_CPU1_SB_DQS_DP<8>")
	)
	(segment
		(start 47.060358 -198.591932)
		(end 47.060104 -198.591678)
		(width 0.1016)
		(layer "F.Cu")
		(net "M_B_CPU1_SB_DQS_DP<8>")
	)
	(segment
		(start 44.735242 -198.58609)
		(end 44.537884 -198.58609)
		(width 0.20066)
		(layer "F.Cu")
		(net "M_B_CPU1_SB_DQS_DP<8>")
	)
	(segment
		(start 47.9679 -198.853044)
		(end 47.462948 -198.853044)
		(width 0.20066)
		(layer "F.Cu")
		(net "M_B_CPU1_SB_DQS_DP<8>")
	)
	(segment
		(start 49.469802 -199.01662)
		(end 49.208436 -199.277986)
		(width 0.20066)
		(layer "F.Cu")
		(net "M_B_CPU1_SB_DQS_DP<8>")
	)
	(segment
		(start 47.060104 -198.591678)
		(end 44.98213 -198.591678)
		(width 0.1016)
		(layer "F.Cu")
		(net "M_B_CPU1_SB_DQS_DP<8>")
	)
	(segment
		(start 49.208436 -199.277986)
		(end 48.603916 -199.277986)
		(width 0.20066)
		(layer "F.Cu")
		(net "M_B_CPU1_SB_DQS_DP<8>")
	)
	(segment
		(start 49.959514 -199.01662)
		(end 49.469802 -199.01662)
		(width 0.20066)
		(layer "F.Cu")
		(net "M_B_CPU1_SB_DQS_DP<8>")
	)
	(segment
		(start 51.064414 -199.01662)
		(end 49.959514 -199.01662)
		(width 0.20066)
		(layer "F.Cu")
		(net "M_B_CPU1_SB_DQS_DP<8>")
	)
	(segment
		(start 47.201836 -198.591932)
		(end 47.060358 -198.591932)
		(width 0.20066)
		(layer "F.Cu")
		(net "M_B_CPU1_SB_DQS_DP<8>")
	)
	(segment
		(start 43.151552 -199.277986)
		(end 42.890186 -199.01662)
		(width 0.20066)
		(layer "F.Cu")
		(net "M_B_CPU1_SB_DQS_DP<8>")
	)
	(segment
		(start 43.908218 -198.855584)
		(end 43.485816 -199.277986)
		(width 0.20066)
		(layer "F.Cu")
		(net "M_B_CPU1_SB_DQS_DP<8>")
	)
	(segment
		(start 48.603916 -199.277986)
		(end 47.9679 -198.853044)
		(width 0.20066)
		(layer "F.Cu")
		(net "M_B_CPU1_SB_DQS_DP<8>")
	)
	(segment
		(start 87.675466 -225.203258)
		(end 87.406734 -225.203258)
		(width 0.088646)
		(layer "In4.Cu")
		(net "M_B_CPU1_SB_DQS_DP<8>")
	)
	(segment
		(start 54.99227 -199.495918)
		(end 51.998626 -199.495918)
		(width 0.18288)
		(layer "In4.Cu")
		(net "M_B_CPU1_SB_DQS_DP<8>")
	)
	(segment
		(start 51.998626 -199.495918)
		(end 51.78679 -199.284082)
		(width 0.18288)
		(layer "In4.Cu")
		(net "M_B_CPU1_SB_DQS_DP<8>")
	)
	(segment
		(start 82.791554 -222.323914)
		(end 82.731864 -222.264224)
		(width 0.088646)
		(layer "In4.Cu")
		(net "M_B_CPU1_SB_DQS_DP<8>")
	)
	(segment
		(start 84.59089 -223.840802)
		(end 83.98891 -223.238822)
		(width 0.088646)
		(layer "In4.Cu")
		(net "M_B_CPU1_SB_DQS_DP<8>")
	)
	(segment
		(start 83.98891 -223.238822)
		(end 83.98891 -223.118172)
		(width 0.088646)
		(layer "In4.Cu")
		(net "M_B_CPU1_SB_DQS_DP<8>")
	)
	(segment
		(start 59.306968 -198.281544)
		(end 58.957972 -198.63054)
		(width 0.18288)
		(layer "In4.Cu")
		(net "M_B_CPU1_SB_DQS_DP<8>")
	)
	(segment
		(start 85.13699 -224.713038)
		(end 85.129624 -224.70872)
		(width 0.088646)
		(layer "In4.Cu")
		(net "M_B_CPU1_SB_DQS_DP<8>")
	)
	(segment
		(start 51.78679 -199.284082)
		(end 51.331876 -199.284082)
		(width 0.18288)
		(layer "In4.Cu")
		(net "M_B_CPU1_SB_DQS_DP<8>")
	)
	(segment
		(start 63.185802 -198.69023)
		(end 62.777116 -198.281544)
		(width 0.18288)
		(layer "In4.Cu")
		(net "M_B_CPU1_SB_DQS_DP<8>")
	)
	(segment
		(start 76.991972 -218.302078)
		(end 71.491348 -204.958696)
		(width 0.18288)
		(layer "In4.Cu")
		(net "M_B_CPU1_SB_DQS_DP<8>")
	)
	(segment
		(start 85.138514 -224.7138)
		(end 85.13699 -224.713038)
		(width 0.088646)
		(layer "In4.Cu")
		(net "M_B_CPU1_SB_DQS_DP<8>")
	)
	(segment
		(start 80.953864 -222.264224)
		(end 76.991972 -218.302078)
		(width 0.18288)
		(layer "In4.Cu")
		(net "M_B_CPU1_SB_DQS_DP<8>")
	)
	(segment
		(start 86.078568 -224.7138)
		(end 86.068154 -224.707704)
		(width 0.088646)
		(layer "In4.Cu")
		(net "M_B_CPU1_SB_DQS_DP<8>")
	)
	(segment
		(start 83.98891 -223.118172)
		(end 83.194652 -222.323914)
		(width 0.088646)
		(layer "In4.Cu")
		(net "M_B_CPU1_SB_DQS_DP<8>")
	)
	(segment
		(start 82.708496 -222.264224)
		(end 80.953864 -222.264224)
		(width 0.18288)
		(layer "In4.Cu")
		(net "M_B_CPU1_SB_DQS_DP<8>")
	)
	(segment
		(start 65.222628 -198.69023)
		(end 63.185802 -198.69023)
		(width 0.18288)
		(layer "In4.Cu")
		(net "M_B_CPU1_SB_DQS_DP<8>")
	)
	(segment
		(start 83.194652 -222.323914)
		(end 82.791554 -222.323914)
		(width 0.088646)
		(layer "In4.Cu")
		(net "M_B_CPU1_SB_DQS_DP<8>")
	)
	(segment
		(start 85.51291 -224.7138)
		(end 85.51291 -224.713546)
		(width 0.088646)
		(layer "In4.Cu")
		(net "M_B_CPU1_SB_DQS_DP<8>")
	)
	(segment
		(start 84.951062 -224.389442)
		(end 84.951062 -224.373948)
		(width 0.088646)
		(layer "In4.Cu")
		(net "M_B_CPU1_SB_DQS_DP<8>")
	)
	(segment
		(start 58.957972 -198.63054)
		(end 55.857648 -198.63054)
		(width 0.18288)
		(layer "In4.Cu")
		(net "M_B_CPU1_SB_DQS_DP<8>")
	)
	(segment
		(start 82.731864 -222.264224)
		(end 82.708496 -222.264224)
		(width 0.088646)
		(layer "In4.Cu")
		(net "M_B_CPU1_SB_DQS_DP<8>")
	)
	(segment
		(start 71.491348 -204.958696)
		(end 65.222628 -198.69023)
		(width 0.18288)
		(layer "In4.Cu")
		(net "M_B_CPU1_SB_DQS_DP<8>")
	)
	(segment
		(start 51.331876 -199.284082)
		(end 51.064414 -199.01662)
		(width 0.18288)
		(layer "In4.Cu")
		(net "M_B_CPU1_SB_DQS_DP<8>")
	)
	(segment
		(start 62.777116 -198.281544)
		(end 59.306968 -198.281544)
		(width 0.18288)
		(layer "In4.Cu")
		(net "M_B_CPU1_SB_DQS_DP<8>")
	)
	(segment
		(start 55.857648 -198.63054)
		(end 54.99227 -199.495918)
		(width 0.18288)
		(layer "In4.Cu")
		(net "M_B_CPU1_SB_DQS_DP<8>")
	)
	(arc
		(start 85.51291 -224.713546)
		(mid 85.325741 -224.76385)
		(end 85.138514 -224.7138)
		(width 0.088646)
		(layer "In4.Cu")
		(net "M_B_CPU1_SB_DQS_DP<8>")
	)
	(arc
		(start 87.406734 -225.203258)
		(mid 87.362204 -225.192504)
		(end 87.32774 -225.162364)
		(width 0.088646)
		(layer "In4.Cu")
		(net "M_B_CPU1_SB_DQS_DP<8>")
	)
	(arc
		(start 87.015066 -224.711768)
		(mid 86.733728 -224.637906)
		(end 86.452964 -224.7138)
		(width 0.088646)
		(layer "In4.Cu")
		(net "M_B_CPU1_SB_DQS_DP<8>")
	)
	(arc
		(start 86.452964 -224.7138)
		(mid 86.265766 -224.763943)
		(end 86.078568 -224.7138)
		(width 0.088646)
		(layer "In4.Cu")
		(net "M_B_CPU1_SB_DQS_DP<8>")
	)
	(arc
		(start 84.605368 -223.854264)
		(mid 84.59804 -223.847629)
		(end 84.59089 -223.840802)
		(width 0.088646)
		(layer "In4.Cu")
		(net "M_B_CPU1_SB_DQS_DP<8>")
	)
	(arc
		(start 87.32774 -225.162364)
		(mid 87.301719 -225.116879)
		(end 87.28456 -225.067368)
		(width 0.088646)
		(layer "In4.Cu")
		(net "M_B_CPU1_SB_DQS_DP<8>")
	)
	(arc
		(start 87.28456 -225.067368)
		(mid 87.188674 -224.864901)
		(end 87.02167 -224.715578)
		(width 0.088646)
		(layer "In4.Cu")
		(net "M_B_CPU1_SB_DQS_DP<8>")
	)
	(arc
		(start 84.951062 -224.373948)
		(mid 84.871692 -224.100214)
		(end 84.668868 -223.899984)
		(width 0.088646)
		(layer "In4.Cu")
		(net "M_B_CPU1_SB_DQS_DP<8>")
	)
	(arc
		(start 85.129624 -224.70872)
		(mid 84.99871 -224.57236)
		(end 84.951062 -224.389442)
		(width 0.088646)
		(layer "In4.Cu")
		(net "M_B_CPU1_SB_DQS_DP<8>")
	)
	(arc
		(start 86.068154 -224.707704)
		(mid 85.789722 -224.637858)
		(end 85.51291 -224.7138)
		(width 0.088646)
		(layer "In4.Cu")
		(net "M_B_CPU1_SB_DQS_DP<8>")
	)
	(arc
		(start 87.02167 -224.715578)
		(mid 87.018359 -224.713689)
		(end 87.015066 -224.711768)
		(width 0.088646)
		(layer "In4.Cu")
		(net "M_B_CPU1_SB_DQS_DP<8>")
	)
	(arc
		(start 84.668868 -223.899984)
		(mid 84.635914 -223.878795)
		(end 84.605368 -223.854264)
		(width 0.088646)
		(layer "In4.Cu")
		(net "M_B_CPU1_SB_DQS_DP<8>")
	)
	(segment
		(start 90.964512 -228.1809)
		(end 90.964512 -227.645214)
		(width 0.20066)
		(layer "F.Cu")
		(net "M_B_CPU1_SB_DQS_DP<7>")
	)
	(segment
		(start 42.890186 -208.366614)
		(end 42.415714 -208.366614)
		(width 0.20066)
		(layer "F.Cu")
		(net "M_B_CPU1_SB_DQS_DP<7>")
	)
	(segment
		(start 47.201836 -207.941926)
		(end 47.060358 -207.941926)
		(width 0.20066)
		(layer "F.Cu")
		(net "M_B_CPU1_SB_DQS_DP<7>")
	)
	(segment
		(start 47.060358 -207.941926)
		(end 47.060104 -207.941672)
		(width 0.1016)
		(layer "F.Cu")
		(net "M_B_CPU1_SB_DQS_DP<7>")
	)
	(segment
		(start 44.98213 -207.941672)
		(end 44.74083 -207.941672)
		(width 0.101854)
		(layer "F.Cu")
		(net "M_B_CPU1_SB_DQS_DP<7>")
	)
	(segment
		(start 44.537884 -207.936084)
		(end 44.26839 -208.205578)
		(width 0.20066)
		(layer "F.Cu")
		(net "M_B_CPU1_SB_DQS_DP<7>")
	)
	(segment
		(start 48.603916 -208.62798)
		(end 47.9679 -208.203038)
		(width 0.20066)
		(layer "F.Cu")
		(net "M_B_CPU1_SB_DQS_DP<7>")
	)
	(segment
		(start 49.469802 -208.366614)
		(end 49.208436 -208.62798)
		(width 0.20066)
		(layer "F.Cu")
		(net "M_B_CPU1_SB_DQS_DP<7>")
	)
	(segment
		(start 47.462948 -208.203038)
		(end 47.201836 -207.941926)
		(width 0.20066)
		(layer "F.Cu")
		(net "M_B_CPU1_SB_DQS_DP<7>")
	)
	(segment
		(start 43.908218 -208.205578)
		(end 43.485816 -208.62798)
		(width 0.20066)
		(layer "F.Cu")
		(net "M_B_CPU1_SB_DQS_DP<7>")
	)
	(segment
		(start 43.151552 -208.62798)
		(end 42.890186 -208.366614)
		(width 0.20066)
		(layer "F.Cu")
		(net "M_B_CPU1_SB_DQS_DP<7>")
	)
	(segment
		(start 43.485816 -208.62798)
		(end 43.151552 -208.62798)
		(width 0.20066)
		(layer "F.Cu")
		(net "M_B_CPU1_SB_DQS_DP<7>")
	)
	(segment
		(start 44.74083 -207.941672)
		(end 44.735242 -207.936084)
		(width 0.101854)
		(layer "F.Cu")
		(net "M_B_CPU1_SB_DQS_DP<7>")
	)
	(segment
		(start 47.9679 -208.203038)
		(end 47.462948 -208.203038)
		(width 0.20066)
		(layer "F.Cu")
		(net "M_B_CPU1_SB_DQS_DP<7>")
	)
	(segment
		(start 51.064414 -208.366614)
		(end 49.959514 -208.366614)
		(width 0.20066)
		(layer "F.Cu")
		(net "M_B_CPU1_SB_DQS_DP<7>")
	)
	(segment
		(start 49.208436 -208.62798)
		(end 48.603916 -208.62798)
		(width 0.20066)
		(layer "F.Cu")
		(net "M_B_CPU1_SB_DQS_DP<7>")
	)
	(segment
		(start 47.060104 -207.941672)
		(end 44.98213 -207.941672)
		(width 0.1016)
		(layer "F.Cu")
		(net "M_B_CPU1_SB_DQS_DP<7>")
	)
	(segment
		(start 49.959514 -208.366614)
		(end 49.469802 -208.366614)
		(width 0.20066)
		(layer "F.Cu")
		(net "M_B_CPU1_SB_DQS_DP<7>")
	)
	(segment
		(start 44.26839 -208.205578)
		(end 43.908218 -208.205578)
		(width 0.20066)
		(layer "F.Cu")
		(net "M_B_CPU1_SB_DQS_DP<7>")
	)
	(segment
		(start 90.964512 -227.645214)
		(end 90.964766 -227.64496)
		(width 0.20066)
		(layer "F.Cu")
		(net "M_B_CPU1_SB_DQS_DP<7>")
	)
	(segment
		(start 44.735242 -207.936084)
		(end 44.537884 -207.936084)
		(width 0.20066)
		(layer "F.Cu")
		(net "M_B_CPU1_SB_DQS_DP<7>")
	)
	(segment
		(start 66.2686 -208.017872)
		(end 66.142362 -207.891634)
		(width 0.18288)
		(layer "In2.Cu")
		(net "M_B_CPU1_SB_DQS_DP<7>")
	)
	(segment
		(start 66.09842 -207.86344)
		(end 65.898268 -207.663288)
		(width 0.16002)
		(layer "In2.Cu")
		(net "M_B_CPU1_SB_DQS_DP<7>")
	)
	(segment
		(start 56.332628 -207.99298)
		(end 56.31688 -207.99298)
		(width 0.16002)
		(layer "In2.Cu")
		(net "M_B_CPU1_SB_DQS_DP<7>")
	)
	(segment
		(start 66.142362 -207.891634)
		(end 66.114168 -207.86344)
		(width 0.16002)
		(layer "In2.Cu")
		(net "M_B_CPU1_SB_DQS_DP<7>")
	)
	(segment
		(start 58.907172 -207.229964)
		(end 58.443368 -207.229964)
		(width 0.18288)
		(layer "In2.Cu")
		(net "M_B_CPU1_SB_DQS_DP<7>")
	)
	(segment
		(start 56.560974 -207.748886)
		(end 56.53278 -207.77708)
		(width 0.16002)
		(layer "In2.Cu")
		(net "M_B_CPU1_SB_DQS_DP<7>")
	)
	(segment
		(start 54.276752 -207.772508)
		(end 54.248558 -207.800702)
		(width 0.16002)
		(layer "In2.Cu")
		(net "M_B_CPU1_SB_DQS_DP<7>")
	)
	(segment
		(start 86.548468 -223.899984)
		(end 86.539578 -223.894904)
		(width 0.088646)
		(layer "In2.Cu")
		(net "M_B_CPU1_SB_DQS_DP<7>")
	)
	(segment
		(start 52.35448 -208.713578)
		(end 52.338732 -208.713578)
		(width 0.16002)
		(layer "In2.Cu")
		(net "M_B_CPU1_SB_DQS_DP<7>")
	)
	(segment
		(start 54.42585 -207.62341)
		(end 54.276752 -207.772508)
		(width 0.18288)
		(layer "In2.Cu")
		(net "M_B_CPU1_SB_DQS_DP<7>")
	)
	(segment
		(start 53.82133 -208.22793)
		(end 52.82438 -208.22793)
		(width 0.18288)
		(layer "In2.Cu")
		(net "M_B_CPU1_SB_DQS_DP<7>")
	)
	(segment
		(start 55.605426 -208.08061)
		(end 55.148226 -207.62341)
		(width 0.18288)
		(layer "In2.Cu")
		(net "M_B_CPU1_SB_DQS_DP<7>")
	)
	(segment
		(start 52.310538 -208.741772)
		(end 52.18938 -208.86293)
		(width 0.18288)
		(layer "In2.Cu")
		(net "M_B_CPU1_SB_DQS_DP<7>")
	)
	(segment
		(start 86.361016 -223.575626)
		(end 86.361016 -223.557084)
		(width 0.088646)
		(layer "In2.Cu")
		(net "M_B_CPU1_SB_DQS_DP<7>")
	)
	(segment
		(start 54.248558 -207.816958)
		(end 54.048914 -208.016602)
		(width 0.16002)
		(layer "In2.Cu")
		(net "M_B_CPU1_SB_DQS_DP<7>")
	)
	(segment
		(start 56.53278 -207.77708)
		(end 56.53278 -207.792828)
		(width 0.16002)
		(layer "In2.Cu")
		(net "M_B_CPU1_SB_DQS_DP<7>")
	)
	(segment
		(start 84.139786 -222.019876)
		(end 70.137782 -208.017872)
		(width 0.18288)
		(layer "In2.Cu")
		(net "M_B_CPU1_SB_DQS_DP<7>")
	)
	(segment
		(start 59.758072 -207.153256)
		(end 59.729878 -207.18145)
		(width 0.16002)
		(layer "In2.Cu")
		(net "M_B_CPU1_SB_DQS_DP<7>")
	)
	(segment
		(start 65.898268 -207.64754)
		(end 65.870074 -207.619346)
		(width 0.16002)
		(layer "In2.Cu")
		(net "M_B_CPU1_SB_DQS_DP<7>")
	)
	(segment
		(start 61.708792 -206.726028)
		(end 60.1853 -206.726028)
		(width 0.18288)
		(layer "In2.Cu")
		(net "M_B_CPU1_SB_DQS_DP<7>")
	)
	(segment
		(start 89.367614 -227.155502)
		(end 89.352882 -227.146866)
		(width 0.088646)
		(layer "In2.Cu")
		(net "M_B_CPU1_SB_DQS_DP<7>")
	)
	(segment
		(start 56.288686 -208.021174)
		(end 56.22925 -208.08061)
		(width 0.18288)
		(layer "In2.Cu")
		(net "M_B_CPU1_SB_DQS_DP<7>")
	)
	(segment
		(start 63.82131 -208.02727)
		(end 63.010034 -208.02727)
		(width 0.18288)
		(layer "In2.Cu")
		(net "M_B_CPU1_SB_DQS_DP<7>")
	)
	(segment
		(start 52.338732 -208.713578)
		(end 52.310538 -208.741772)
		(width 0.16002)
		(layer "In2.Cu")
		(net "M_B_CPU1_SB_DQS_DP<7>")
	)
	(segment
		(start 63.946786 -207.901794)
		(end 63.82131 -208.02727)
		(width 0.18288)
		(layer "In2.Cu")
		(net "M_B_CPU1_SB_DQS_DP<7>")
	)
	(segment
		(start 64.50457 -207.34401)
		(end 64.219074 -207.629506)
		(width 0.18288)
		(layer "In2.Cu")
		(net "M_B_CPU1_SB_DQS_DP<7>")
	)
	(segment
		(start 54.004464 -208.044796)
		(end 53.82133 -208.22793)
		(width 0.18288)
		(layer "In2.Cu")
		(net "M_B_CPU1_SB_DQS_DP<7>")
	)
	(segment
		(start 90.31351 -227.159058)
		(end 90.292682 -227.146866)
		(width 0.088646)
		(layer "In2.Cu")
		(net "M_B_CPU1_SB_DQS_DP<7>")
	)
	(segment
		(start 87.949278 -225.69805)
		(end 87.958168 -225.69297)
		(width 0.088646)
		(layer "In2.Cu")
		(net "M_B_CPU1_SB_DQS_DP<7>")
	)
	(segment
		(start 62.164214 -207.18145)
		(end 62.13602 -207.153256)
		(width 0.16002)
		(layer "In2.Cu")
		(net "M_B_CPU1_SB_DQS_DP<7>")
	)
	(segment
		(start 56.53278 -207.792828)
		(end 56.332628 -207.99298)
		(width 0.16002)
		(layer "In2.Cu")
		(net "M_B_CPU1_SB_DQS_DP<7>")
	)
	(segment
		(start 61.92012 -206.937356)
		(end 61.891926 -206.909162)
		(width 0.16002)
		(layer "In2.Cu")
		(net "M_B_CPU1_SB_DQS_DP<7>")
	)
	(segment
		(start 58.443368 -207.229964)
		(end 58.163714 -207.509618)
		(width 0.18288)
		(layer "In2.Cu")
		(net "M_B_CPU1_SB_DQS_DP<7>")
	)
	(segment
		(start 61.92012 -206.953104)
		(end 61.92012 -206.937356)
		(width 0.16002)
		(layer "In2.Cu")
		(net "M_B_CPU1_SB_DQS_DP<7>")
	)
	(segment
		(start 86.078568 -223.085914)
		(end 86.069678 -223.080834)
		(width 0.088646)
		(layer "In2.Cu")
		(net "M_B_CPU1_SB_DQS_DP<7>")
	)
	(segment
		(start 57.795414 -207.509618)
		(end 57.718706 -207.43291)
		(width 0.18288)
		(layer "In2.Cu")
		(net "M_B_CPU1_SB_DQS_DP<7>")
	)
	(segment
		(start 86.830916 -224.389442)
		(end 86.830916 -224.379536)
		(width 0.088646)
		(layer "In2.Cu")
		(net "M_B_CPU1_SB_DQS_DP<7>")
	)
	(segment
		(start 64.19088 -207.673448)
		(end 63.990728 -207.8736)
		(width 0.16002)
		(layer "In2.Cu")
		(net "M_B_CPU1_SB_DQS_DP<7>")
	)
	(segment
		(start 64.19088 -207.6577)
		(end 64.19088 -207.673448)
		(width 0.16002)
		(layer "In2.Cu")
		(net "M_B_CPU1_SB_DQS_DP<7>")
	)
	(segment
		(start 52.82438 -208.22793)
		(end 52.582826 -208.469484)
		(width 0.18288)
		(layer "In2.Cu")
		(net "M_B_CPU1_SB_DQS_DP<7>")
	)
	(segment
		(start 54.048914 -208.016602)
		(end 54.032658 -208.016602)
		(width 0.16002)
		(layer "In2.Cu")
		(net "M_B_CPU1_SB_DQS_DP<7>")
	)
	(segment
		(start 59.406028 -207.5053)
		(end 59.182508 -207.5053)
		(width 0.18288)
		(layer "In2.Cu")
		(net "M_B_CPU1_SB_DQS_DP<7>")
	)
	(segment
		(start 59.182508 -207.5053)
		(end 58.907172 -207.229964)
		(width 0.18288)
		(layer "In2.Cu")
		(net "M_B_CPU1_SB_DQS_DP<7>")
	)
	(segment
		(start 63.990728 -207.8736)
		(end 63.97498 -207.8736)
		(width 0.16002)
		(layer "In2.Cu")
		(net "M_B_CPU1_SB_DQS_DP<7>")
	)
	(segment
		(start 52.18938 -208.86293)
		(end 51.89982 -208.86293)
		(width 0.18288)
		(layer "In2.Cu")
		(net "M_B_CPU1_SB_DQS_DP<7>")
	)
	(segment
		(start 63.97498 -207.8736)
		(end 63.946786 -207.901794)
		(width 0.16002)
		(layer "In2.Cu")
		(net "M_B_CPU1_SB_DQS_DP<7>")
	)
	(segment
		(start 62.120272 -207.153256)
		(end 61.92012 -206.953104)
		(width 0.16002)
		(layer "In2.Cu")
		(net "M_B_CPU1_SB_DQS_DP<7>")
	)
	(segment
		(start 70.137782 -208.017872)
		(end 66.2686 -208.017872)
		(width 0.18288)
		(layer "In2.Cu")
		(net "M_B_CPU1_SB_DQS_DP<7>")
	)
	(segment
		(start 85.65642 -222.302832)
		(end 85.4329 -222.079566)
		(width 0.088646)
		(layer "In2.Cu")
		(net "M_B_CPU1_SB_DQS_DP<7>")
	)
	(segment
		(start 51.335432 -208.637632)
		(end 51.064414 -208.366614)
		(width 0.18288)
		(layer "In2.Cu")
		(net "M_B_CPU1_SB_DQS_DP<7>")
	)
	(segment
		(start 59.973972 -206.937356)
		(end 59.973972 -206.953104)
		(width 0.16002)
		(layer "In2.Cu")
		(net "M_B_CPU1_SB_DQS_DP<7>")
	)
	(segment
		(start 59.77382 -207.153256)
		(end 59.758072 -207.153256)
		(width 0.16002)
		(layer "In2.Cu")
		(net "M_B_CPU1_SB_DQS_DP<7>")
	)
	(segment
		(start 51.89982 -208.86293)
		(end 51.674522 -208.637632)
		(width 0.18288)
		(layer "In2.Cu")
		(net "M_B_CPU1_SB_DQS_DP<7>")
	)
	(segment
		(start 88.240616 -226.83978)
		(end 88.240616 -226.821238)
		(width 0.088646)
		(layer "In2.Cu")
		(net "M_B_CPU1_SB_DQS_DP<7>")
	)
	(segment
		(start 90.964766 -227.64496)
		(end 90.651838 -227.64496)
		(width 0.088646)
		(layer "In2.Cu")
		(net "M_B_CPU1_SB_DQS_DP<7>")
	)
	(segment
		(start 51.674522 -208.637632)
		(end 51.335432 -208.637632)
		(width 0.18288)
		(layer "In2.Cu")
		(net "M_B_CPU1_SB_DQS_DP<7>")
	)
	(segment
		(start 63.010034 -208.02727)
		(end 62.164214 -207.18145)
		(width 0.18288)
		(layer "In2.Cu")
		(net "M_B_CPU1_SB_DQS_DP<7>")
	)
	(segment
		(start 84.705952 -222.079566)
		(end 84.646262 -222.019876)
		(width 0.088646)
		(layer "In2.Cu")
		(net "M_B_CPU1_SB_DQS_DP<7>")
	)
	(segment
		(start 65.594738 -207.34401)
		(end 64.50457 -207.34401)
		(width 0.18288)
		(layer "In2.Cu")
		(net "M_B_CPU1_SB_DQS_DP<7>")
	)
	(segment
		(start 56.22925 -208.08061)
		(end 55.605426 -208.08061)
		(width 0.18288)
		(layer "In2.Cu")
		(net "M_B_CPU1_SB_DQS_DP<7>")
	)
	(segment
		(start 66.114168 -207.86344)
		(end 66.09842 -207.86344)
		(width 0.16002)
		(layer "In2.Cu")
		(net "M_B_CPU1_SB_DQS_DP<7>")
	)
	(segment
		(start 52.554632 -208.513426)
		(end 52.35448 -208.713578)
		(width 0.16002)
		(layer "In2.Cu")
		(net "M_B_CPU1_SB_DQS_DP<7>")
	)
	(segment
		(start 56.87695 -207.43291)
		(end 56.560974 -207.748886)
		(width 0.18288)
		(layer "In2.Cu")
		(net "M_B_CPU1_SB_DQS_DP<7>")
	)
	(segment
		(start 87.958168 -226.341686)
		(end 87.950294 -226.337114)
		(width 0.088646)
		(layer "In2.Cu")
		(net "M_B_CPU1_SB_DQS_DP<7>")
	)
	(segment
		(start 65.870074 -207.619346)
		(end 65.594738 -207.34401)
		(width 0.18288)
		(layer "In2.Cu")
		(net "M_B_CPU1_SB_DQS_DP<7>")
	)
	(segment
		(start 59.729878 -207.18145)
		(end 59.406028 -207.5053)
		(width 0.18288)
		(layer "In2.Cu")
		(net "M_B_CPU1_SB_DQS_DP<7>")
	)
	(segment
		(start 64.219074 -207.629506)
		(end 64.19088 -207.6577)
		(width 0.16002)
		(layer "In2.Cu")
		(net "M_B_CPU1_SB_DQS_DP<7>")
	)
	(segment
		(start 55.148226 -207.62341)
		(end 54.42585 -207.62341)
		(width 0.18288)
		(layer "In2.Cu")
		(net "M_B_CPU1_SB_DQS_DP<7>")
	)
	(segment
		(start 57.718706 -207.43291)
		(end 56.87695 -207.43291)
		(width 0.18288)
		(layer "In2.Cu")
		(net "M_B_CPU1_SB_DQS_DP<7>")
	)
	(segment
		(start 85.4329 -222.079566)
		(end 84.705952 -222.079566)
		(width 0.088646)
		(layer "In2.Cu")
		(net "M_B_CPU1_SB_DQS_DP<7>")
	)
	(segment
		(start 60.1853 -206.726028)
		(end 60.002166 -206.909162)
		(width 0.18288)
		(layer "In2.Cu")
		(net "M_B_CPU1_SB_DQS_DP<7>")
	)
	(segment
		(start 52.582826 -208.469484)
		(end 52.554632 -208.497678)
		(width 0.16002)
		(layer "In2.Cu")
		(net "M_B_CPU1_SB_DQS_DP<7>")
	)
	(segment
		(start 84.646262 -222.019876)
		(end 84.139786 -222.019876)
		(width 0.18288)
		(layer "In2.Cu")
		(net "M_B_CPU1_SB_DQS_DP<7>")
	)
	(segment
		(start 65.898268 -207.663288)
		(end 65.898268 -207.64754)
		(width 0.16002)
		(layer "In2.Cu")
		(net "M_B_CPU1_SB_DQS_DP<7>")
	)
	(segment
		(start 58.163714 -207.509618)
		(end 57.795414 -207.509618)
		(width 0.18288)
		(layer "In2.Cu")
		(net "M_B_CPU1_SB_DQS_DP<7>")
	)
	(segment
		(start 54.032658 -208.016602)
		(end 54.004464 -208.044796)
		(width 0.16002)
		(layer "In2.Cu")
		(net "M_B_CPU1_SB_DQS_DP<7>")
	)
	(segment
		(start 59.973972 -206.953104)
		(end 59.77382 -207.153256)
		(width 0.16002)
		(layer "In2.Cu")
		(net "M_B_CPU1_SB_DQS_DP<7>")
	)
	(segment
		(start 90.651838 -227.64496)
		(end 90.586306 -227.579428)
		(width 0.088646)
		(layer "In2.Cu")
		(net "M_B_CPU1_SB_DQS_DP<7>")
	)
	(segment
		(start 52.554632 -208.497678)
		(end 52.554632 -208.513426)
		(width 0.16002)
		(layer "In2.Cu")
		(net "M_B_CPU1_SB_DQS_DP<7>")
	)
	(segment
		(start 54.248558 -207.800702)
		(end 54.248558 -207.816958)
		(width 0.16002)
		(layer "In2.Cu")
		(net "M_B_CPU1_SB_DQS_DP<7>")
	)
	(segment
		(start 87.950294 -226.337114)
		(end 87.949278 -226.336606)
		(width 0.088646)
		(layer "In2.Cu")
		(net "M_B_CPU1_SB_DQS_DP<7>")
	)
	(segment
		(start 56.31688 -207.99298)
		(end 56.288686 -208.021174)
		(width 0.16002)
		(layer "In2.Cu")
		(net "M_B_CPU1_SB_DQS_DP<7>")
	)
	(segment
		(start 62.13602 -207.153256)
		(end 62.120272 -207.153256)
		(width 0.16002)
		(layer "In2.Cu")
		(net "M_B_CPU1_SB_DQS_DP<7>")
	)
	(segment
		(start 60.002166 -206.909162)
		(end 59.973972 -206.937356)
		(width 0.16002)
		(layer "In2.Cu")
		(net "M_B_CPU1_SB_DQS_DP<7>")
	)
	(segment
		(start 61.891926 -206.909162)
		(end 61.708792 -206.726028)
		(width 0.18288)
		(layer "In2.Cu")
		(net "M_B_CPU1_SB_DQS_DP<7>")
	)
	(arc
		(start 90.586306 -227.579428)
		(mid 90.499062 -227.33734)
		(end 90.31351 -227.159058)
		(width 0.088646)
		(layer "In2.Cu")
		(net "M_B_CPU1_SB_DQS_DP<7>")
	)
	(arc
		(start 89.74201 -227.155502)
		(mid 89.554812 -227.205645)
		(end 89.367614 -227.155502)
		(width 0.088646)
		(layer "In2.Cu")
		(net "M_B_CPU1_SB_DQS_DP<7>")
	)
	(arc
		(start 86.830916 -224.379536)
		(mid 86.752805 -224.102587)
		(end 86.548468 -223.899984)
		(width 0.088646)
		(layer "In2.Cu")
		(net "M_B_CPU1_SB_DQS_DP<7>")
	)
	(arc
		(start 86.539578 -223.894904)
		(mid 86.408664 -223.758544)
		(end 86.361016 -223.575626)
		(width 0.088646)
		(layer "In2.Cu")
		(net "M_B_CPU1_SB_DQS_DP<7>")
	)
	(arc
		(start 89.352882 -227.146866)
		(mid 89.076407 -227.079546)
		(end 88.80221 -227.155502)
		(width 0.088646)
		(layer "In2.Cu")
		(net "M_B_CPU1_SB_DQS_DP<7>")
	)
	(arc
		(start 88.80221 -227.155502)
		(mid 88.431487 -227.157594)
		(end 88.240616 -226.83978)
		(width 0.088646)
		(layer "In2.Cu")
		(net "M_B_CPU1_SB_DQS_DP<7>")
	)
	(arc
		(start 86.069678 -223.080834)
		(mid 85.938764 -222.944474)
		(end 85.891116 -222.761556)
		(width 0.088646)
		(layer "In2.Cu")
		(net "M_B_CPU1_SB_DQS_DP<7>")
	)
	(arc
		(start 85.891116 -222.761556)
		(mid 85.82909 -222.50389)
		(end 85.65642 -222.302832)
		(width 0.088646)
		(layer "In2.Cu")
		(net "M_B_CPU1_SB_DQS_DP<7>")
	)
	(arc
		(start 87.949278 -226.336606)
		(mid 87.770681 -226.017328)
		(end 87.949278 -225.69805)
		(width 0.088646)
		(layer "In2.Cu")
		(net "M_B_CPU1_SB_DQS_DP<7>")
	)
	(arc
		(start 90.292682 -227.146866)
		(mid 90.016207 -227.079546)
		(end 89.74201 -227.155502)
		(width 0.088646)
		(layer "In2.Cu")
		(net "M_B_CPU1_SB_DQS_DP<7>")
	)
	(arc
		(start 87.392764 -224.7138)
		(mid 87.018289 -224.713754)
		(end 86.830916 -224.389442)
		(width 0.088646)
		(layer "In2.Cu")
		(net "M_B_CPU1_SB_DQS_DP<7>")
	)
	(arc
		(start 87.958168 -225.69297)
		(mid 88.165146 -224.920501)
		(end 87.392764 -224.7138)
		(width 0.088646)
		(layer "In2.Cu")
		(net "M_B_CPU1_SB_DQS_DP<7>")
	)
	(arc
		(start 88.240616 -226.821238)
		(mid 88.162505 -226.544289)
		(end 87.958168 -226.341686)
		(width 0.088646)
		(layer "In2.Cu")
		(net "M_B_CPU1_SB_DQS_DP<7>")
	)
	(arc
		(start 86.361016 -223.557084)
		(mid 86.280854 -223.284895)
		(end 86.078568 -223.085914)
		(width 0.088646)
		(layer "In2.Cu")
		(net "M_B_CPU1_SB_DQS_DP<7>")
	)
	(segment
		(start 44.98213 -217.291666)
		(end 44.74083 -217.291666)
		(width 0.101854)
		(layer "F.Cu")
		(net "M_B_CPU1_SB_DQS_DP<6>")
	)
	(segment
		(start 49.959514 -217.716608)
		(end 49.469802 -217.716608)
		(width 0.20066)
		(layer "F.Cu")
		(net "M_B_CPU1_SB_DQS_DP<6>")
	)
	(segment
		(start 47.060104 -217.291666)
		(end 44.98213 -217.291666)
		(width 0.1016)
		(layer "F.Cu")
		(net "M_B_CPU1_SB_DQS_DP<6>")
	)
	(segment
		(start 44.74083 -217.291666)
		(end 44.735242 -217.286078)
		(width 0.101854)
		(layer "F.Cu")
		(net "M_B_CPU1_SB_DQS_DP<6>")
	)
	(segment
		(start 90.964766 -233.06405)
		(end 90.964766 -232.528364)
		(width 0.20066)
		(layer "F.Cu")
		(net "M_B_CPU1_SB_DQS_DP<6>")
	)
	(segment
		(start 90.964512 -233.064304)
		(end 90.964766 -233.06405)
		(width 0.20066)
		(layer "F.Cu")
		(net "M_B_CPU1_SB_DQS_DP<6>")
	)
	(segment
		(start 47.462948 -217.553032)
		(end 47.201836 -217.29192)
		(width 0.20066)
		(layer "F.Cu")
		(net "M_B_CPU1_SB_DQS_DP<6>")
	)
	(segment
		(start 43.908218 -217.555572)
		(end 43.485816 -217.977974)
		(width 0.20066)
		(layer "F.Cu")
		(net "M_B_CPU1_SB_DQS_DP<6>")
	)
	(segment
		(start 43.151552 -217.977974)
		(end 42.890186 -217.716608)
		(width 0.20066)
		(layer "F.Cu")
		(net "M_B_CPU1_SB_DQS_DP<6>")
	)
	(segment
		(start 48.603916 -217.977974)
		(end 47.9679 -217.553032)
		(width 0.20066)
		(layer "F.Cu")
		(net "M_B_CPU1_SB_DQS_DP<6>")
	)
	(segment
		(start 42.890186 -217.716608)
		(end 42.415714 -217.716608)
		(width 0.20066)
		(layer "F.Cu")
		(net "M_B_CPU1_SB_DQS_DP<6>")
	)
	(segment
		(start 51.064414 -217.716608)
		(end 49.959514 -217.716608)
		(width 0.20066)
		(layer "F.Cu")
		(net "M_B_CPU1_SB_DQS_DP<6>")
	)
	(segment
		(start 47.9679 -217.553032)
		(end 47.462948 -217.553032)
		(width 0.20066)
		(layer "F.Cu")
		(net "M_B_CPU1_SB_DQS_DP<6>")
	)
	(segment
		(start 49.469802 -217.716608)
		(end 49.208436 -217.977974)
		(width 0.20066)
		(layer "F.Cu")
		(net "M_B_CPU1_SB_DQS_DP<6>")
	)
	(segment
		(start 47.201836 -217.29192)
		(end 47.060358 -217.29192)
		(width 0.20066)
		(layer "F.Cu")
		(net "M_B_CPU1_SB_DQS_DP<6>")
	)
	(segment
		(start 49.208436 -217.977974)
		(end 48.603916 -217.977974)
		(width 0.20066)
		(layer "F.Cu")
		(net "M_B_CPU1_SB_DQS_DP<6>")
	)
	(segment
		(start 43.485816 -217.977974)
		(end 43.151552 -217.977974)
		(width 0.20066)
		(layer "F.Cu")
		(net "M_B_CPU1_SB_DQS_DP<6>")
	)
	(segment
		(start 44.26839 -217.555572)
		(end 43.908218 -217.555572)
		(width 0.20066)
		(layer "F.Cu")
		(net "M_B_CPU1_SB_DQS_DP<6>")
	)
	(segment
		(start 44.537884 -217.286078)
		(end 44.26839 -217.555572)
		(width 0.20066)
		(layer "F.Cu")
		(net "M_B_CPU1_SB_DQS_DP<6>")
	)
	(segment
		(start 47.060358 -217.29192)
		(end 47.060104 -217.291666)
		(width 0.1016)
		(layer "F.Cu")
		(net "M_B_CPU1_SB_DQS_DP<6>")
	)
	(segment
		(start 44.735242 -217.286078)
		(end 44.537884 -217.286078)
		(width 0.20066)
		(layer "F.Cu")
		(net "M_B_CPU1_SB_DQS_DP<6>")
	)
	(segment
		(start 66.22034 -217.353134)
		(end 66.020188 -217.152982)
		(width 0.16002)
		(layer "In2.Cu")
		(net "M_B_CPU1_SB_DQS_DP<6>")
	)
	(segment
		(start 69.812662 -217.429588)
		(end 66.312542 -217.429588)
		(width 0.18288)
		(layer "In2.Cu")
		(net "M_B_CPU1_SB_DQS_DP<6>")
	)
	(segment
		(start 58.788554 -218.39555)
		(end 58.50128 -218.682824)
		(width 0.18288)
		(layer "In2.Cu")
		(net "M_B_CPU1_SB_DQS_DP<6>")
	)
	(segment
		(start 56.505348 -218.682824)
		(end 56.167274 -218.34475)
		(width 0.18288)
		(layer "In2.Cu")
		(net "M_B_CPU1_SB_DQS_DP<6>")
	)
	(segment
		(start 51.663092 -217.981022)
		(end 51.328828 -217.981022)
		(width 0.18288)
		(layer "In2.Cu")
		(net "M_B_CPU1_SB_DQS_DP<6>")
	)
	(segment
		(start 59.729878 -218.231466)
		(end 59.565794 -218.39555)
		(width 0.18288)
		(layer "In2.Cu")
		(net "M_B_CPU1_SB_DQS_DP<6>")
	)
	(segment
		(start 78.496668 -226.296982)
		(end 78.496668 -226.113594)
		(width 0.18288)
		(layer "In2.Cu")
		(net "M_B_CPU1_SB_DQS_DP<6>")
	)
	(segment
		(start 65.827402 -216.944448)
		(end 64.266826 -216.944448)
		(width 0.18288)
		(layer "In2.Cu")
		(net "M_B_CPU1_SB_DQS_DP<6>")
	)
	(segment
		(start 66.236088 -217.353134)
		(end 66.22034 -217.353134)
		(width 0.16002)
		(layer "In2.Cu")
		(net "M_B_CPU1_SB_DQS_DP<6>")
	)
	(segment
		(start 52.138834 -218.26347)
		(end 51.94554 -218.26347)
		(width 0.18288)
		(layer "In2.Cu")
		(net "M_B_CPU1_SB_DQS_DP<6>")
	)
	(segment
		(start 58.473086 -218.727274)
		(end 58.273442 -218.926918)
		(width 0.16002)
		(layer "In2.Cu")
		(net "M_B_CPU1_SB_DQS_DP<6>")
	)
	(segment
		(start 56.533542 -218.711018)
		(end 56.505348 -218.682824)
		(width 0.16002)
		(layer "In2.Cu")
		(net "M_B_CPU1_SB_DQS_DP<6>")
	)
	(segment
		(start 78.496668 -226.113594)
		(end 69.812662 -217.429588)
		(width 0.18288)
		(layer "In2.Cu")
		(net "M_B_CPU1_SB_DQS_DP<6>")
	)
	(segment
		(start 64.07404 -217.137234)
		(end 64.07404 -217.152982)
		(width 0.16002)
		(layer "In2.Cu")
		(net "M_B_CPU1_SB_DQS_DP<6>")
	)
	(segment
		(start 62.146434 -218.203526)
		(end 62.11824 -218.175332)
		(width 0.16002)
		(layer "In2.Cu")
		(net "M_B_CPU1_SB_DQS_DP<6>")
	)
	(segment
		(start 54.37632 -218.00312)
		(end 54.37632 -217.987372)
		(width 0.16002)
		(layer "In2.Cu")
		(net "M_B_CPU1_SB_DQS_DP<6>")
	)
	(segment
		(start 52.208938 -218.193366)
		(end 52.138834 -218.26347)
		(width 0.18288)
		(layer "In2.Cu")
		(net "M_B_CPU1_SB_DQS_DP<6>")
	)
	(segment
		(start 56.89219 -219.069666)
		(end 56.777636 -218.955112)
		(width 0.18288)
		(layer "In2.Cu")
		(net "M_B_CPU1_SB_DQS_DP<6>")
	)
	(segment
		(start 59.77382 -218.203272)
		(end 59.758072 -218.203272)
		(width 0.16002)
		(layer "In2.Cu")
		(net "M_B_CPU1_SB_DQS_DP<6>")
	)
	(segment
		(start 85.057996 -232.03027)
		(end 85.043264 -232.038906)
		(width 0.088646)
		(layer "In2.Cu")
		(net "M_B_CPU1_SB_DQS_DP<6>")
	)
	(segment
		(start 58.114438 -219.069666)
		(end 56.89219 -219.069666)
		(width 0.18288)
		(layer "In2.Cu")
		(net "M_B_CPU1_SB_DQS_DP<6>")
	)
	(segment
		(start 64.07404 -217.152982)
		(end 63.873888 -217.353134)
		(width 0.16002)
		(layer "In2.Cu")
		(net "M_B_CPU1_SB_DQS_DP<6>")
	)
	(segment
		(start 64.266826 -216.944448)
		(end 64.102234 -217.10904)
		(width 0.18288)
		(layer "In2.Cu")
		(net "M_B_CPU1_SB_DQS_DP<6>")
	)
	(segment
		(start 59.973972 -217.987372)
		(end 59.973972 -218.00312)
		(width 0.16002)
		(layer "In2.Cu")
		(net "M_B_CPU1_SB_DQS_DP<6>")
	)
	(segment
		(start 51.328828 -217.981022)
		(end 51.064414 -217.716608)
		(width 0.18288)
		(layer "In2.Cu")
		(net "M_B_CPU1_SB_DQS_DP<6>")
	)
	(segment
		(start 54.59222 -218.203272)
		(end 54.576472 -218.203272)
		(width 0.16002)
		(layer "In2.Cu")
		(net "M_B_CPU1_SB_DQS_DP<6>")
	)
	(segment
		(start 61.737494 -217.794586)
		(end 60.166758 -217.794586)
		(width 0.18288)
		(layer "In2.Cu")
		(net "M_B_CPU1_SB_DQS_DP<6>")
	)
	(segment
		(start 84.668868 -232.038906)
		(end 84.668614 -232.039414)
		(width 0.088646)
		(layer "In2.Cu")
		(net "M_B_CPU1_SB_DQS_DP<6>")
	)
	(segment
		(start 90.652092 -232.528364)
		(end 90.586306 -232.462578)
		(width 0.088646)
		(layer "In2.Cu")
		(net "M_B_CPU1_SB_DQS_DP<6>")
	)
	(segment
		(start 58.257186 -218.926918)
		(end 58.228992 -218.955112)
		(width 0.16002)
		(layer "In2.Cu")
		(net "M_B_CPU1_SB_DQS_DP<6>")
	)
	(segment
		(start 83.843876 -231.728264)
		(end 83.84413 -231.644444)
		(width 0.088646)
		(layer "In2.Cu")
		(net "M_B_CPU1_SB_DQS_DP<6>")
	)
	(segment
		(start 84.07781 -231.96296)
		(end 83.843876 -231.728264)
		(width 0.088646)
		(layer "In2.Cu")
		(net "M_B_CPU1_SB_DQS_DP<6>")
	)
	(segment
		(start 61.874146 -217.931238)
		(end 61.737494 -217.794586)
		(width 0.18288)
		(layer "In2.Cu")
		(net "M_B_CPU1_SB_DQS_DP<6>")
	)
	(segment
		(start 58.50128 -218.682824)
		(end 58.473086 -218.711018)
		(width 0.16002)
		(layer "In2.Cu")
		(net "M_B_CPU1_SB_DQS_DP<6>")
	)
	(segment
		(start 63.162942 -217.592656)
		(end 62.48781 -218.267788)
		(width 0.18288)
		(layer "In2.Cu")
		(net "M_B_CPU1_SB_DQS_DP<6>")
	)
	(segment
		(start 52.453032 -217.96502)
		(end 52.25288 -218.165172)
		(width 0.16002)
		(layer "In2.Cu")
		(net "M_B_CPU1_SB_DQS_DP<6>")
	)
	(segment
		(start 66.020188 -217.152982)
		(end 66.020188 -217.137234)
		(width 0.16002)
		(layer "In2.Cu")
		(net "M_B_CPU1_SB_DQS_DP<6>")
	)
	(segment
		(start 61.90234 -217.959432)
		(end 61.874146 -217.931238)
		(width 0.16002)
		(layer "In2.Cu")
		(net "M_B_CPU1_SB_DQS_DP<6>")
	)
	(segment
		(start 63.85814 -217.353134)
		(end 63.829946 -217.381328)
		(width 0.16002)
		(layer "In2.Cu")
		(net "M_B_CPU1_SB_DQS_DP<6>")
	)
	(segment
		(start 60.166758 -217.794586)
		(end 60.002166 -217.959178)
		(width 0.18288)
		(layer "In2.Cu")
		(net "M_B_CPU1_SB_DQS_DP<6>")
	)
	(segment
		(start 52.453032 -217.949272)
		(end 52.453032 -217.96502)
		(width 0.16002)
		(layer "In2.Cu")
		(net "M_B_CPU1_SB_DQS_DP<6>")
	)
	(segment
		(start 65.991994 -217.10904)
		(end 65.827402 -216.944448)
		(width 0.18288)
		(layer "In2.Cu")
		(net "M_B_CPU1_SB_DQS_DP<6>")
	)
	(segment
		(start 66.264282 -217.381328)
		(end 66.236088 -217.353134)
		(width 0.16002)
		(layer "In2.Cu")
		(net "M_B_CPU1_SB_DQS_DP<6>")
	)
	(segment
		(start 58.228992 -218.955112)
		(end 58.114438 -219.069666)
		(width 0.18288)
		(layer "In2.Cu")
		(net "M_B_CPU1_SB_DQS_DP<6>")
	)
	(segment
		(start 59.565794 -218.39555)
		(end 58.788554 -218.39555)
		(width 0.18288)
		(layer "In2.Cu")
		(net "M_B_CPU1_SB_DQS_DP<6>")
	)
	(segment
		(start 56.533542 -218.727274)
		(end 56.533542 -218.711018)
		(width 0.16002)
		(layer "In2.Cu")
		(net "M_B_CPU1_SB_DQS_DP<6>")
	)
	(segment
		(start 83.84413 -231.644444)
		(end 78.496668 -226.296982)
		(width 0.18288)
		(layer "In2.Cu")
		(net "M_B_CPU1_SB_DQS_DP<6>")
	)
	(segment
		(start 54.348126 -217.959178)
		(end 54.169818 -217.78087)
		(width 0.18288)
		(layer "In2.Cu")
		(net "M_B_CPU1_SB_DQS_DP<6>")
	)
	(segment
		(start 66.312542 -217.429588)
		(end 66.264282 -217.381328)
		(width 0.18288)
		(layer "In2.Cu")
		(net "M_B_CPU1_SB_DQS_DP<6>")
	)
	(segment
		(start 54.576472 -218.203272)
		(end 54.37632 -218.00312)
		(width 0.16002)
		(layer "In2.Cu")
		(net "M_B_CPU1_SB_DQS_DP<6>")
	)
	(segment
		(start 51.94554 -218.26347)
		(end 51.663092 -217.981022)
		(width 0.18288)
		(layer "In2.Cu")
		(net "M_B_CPU1_SB_DQS_DP<6>")
	)
	(segment
		(start 54.169818 -217.78087)
		(end 52.621434 -217.78087)
		(width 0.18288)
		(layer "In2.Cu")
		(net "M_B_CPU1_SB_DQS_DP<6>")
	)
	(segment
		(start 66.020188 -217.137234)
		(end 65.991994 -217.10904)
		(width 0.16002)
		(layer "In2.Cu")
		(net "M_B_CPU1_SB_DQS_DP<6>")
	)
	(segment
		(start 62.48781 -218.267788)
		(end 62.210696 -218.267788)
		(width 0.18288)
		(layer "In2.Cu")
		(net "M_B_CPU1_SB_DQS_DP<6>")
	)
	(segment
		(start 63.829946 -217.381328)
		(end 63.618618 -217.592656)
		(width 0.18288)
		(layer "In2.Cu")
		(net "M_B_CPU1_SB_DQS_DP<6>")
	)
	(segment
		(start 56.749442 -218.926918)
		(end 56.733186 -218.926918)
		(width 0.16002)
		(layer "In2.Cu")
		(net "M_B_CPU1_SB_DQS_DP<6>")
	)
	(segment
		(start 60.002166 -217.959178)
		(end 59.973972 -217.987372)
		(width 0.16002)
		(layer "In2.Cu")
		(net "M_B_CPU1_SB_DQS_DP<6>")
	)
	(segment
		(start 62.102492 -218.175332)
		(end 61.90234 -217.97518)
		(width 0.16002)
		(layer "In2.Cu")
		(net "M_B_CPU1_SB_DQS_DP<6>")
	)
	(segment
		(start 56.733186 -218.926918)
		(end 56.533542 -218.727274)
		(width 0.16002)
		(layer "In2.Cu")
		(net "M_B_CPU1_SB_DQS_DP<6>")
	)
	(segment
		(start 84.38642 -231.96296)
		(end 84.07781 -231.96296)
		(width 0.088646)
		(layer "In2.Cu")
		(net "M_B_CPU1_SB_DQS_DP<6>")
	)
	(segment
		(start 90.964766 -232.528364)
		(end 90.652092 -232.528364)
		(width 0.088646)
		(layer "In2.Cu")
		(net "M_B_CPU1_SB_DQS_DP<6>")
	)
	(segment
		(start 61.90234 -217.97518)
		(end 61.90234 -217.959432)
		(width 0.16002)
		(layer "In2.Cu")
		(net "M_B_CPU1_SB_DQS_DP<6>")
	)
	(segment
		(start 56.167274 -218.34475)
		(end 54.733698 -218.34475)
		(width 0.18288)
		(layer "In2.Cu")
		(net "M_B_CPU1_SB_DQS_DP<6>")
	)
	(segment
		(start 89.367614 -232.038906)
		(end 89.352882 -232.03027)
		(width 0.088646)
		(layer "In2.Cu")
		(net "M_B_CPU1_SB_DQS_DP<6>")
	)
	(segment
		(start 56.777636 -218.955112)
		(end 56.749442 -218.926918)
		(width 0.16002)
		(layer "In2.Cu")
		(net "M_B_CPU1_SB_DQS_DP<6>")
	)
	(segment
		(start 59.758072 -218.203272)
		(end 59.729878 -218.231466)
		(width 0.16002)
		(layer "In2.Cu")
		(net "M_B_CPU1_SB_DQS_DP<6>")
	)
	(segment
		(start 62.210696 -218.267788)
		(end 62.146434 -218.203526)
		(width 0.18288)
		(layer "In2.Cu")
		(net "M_B_CPU1_SB_DQS_DP<6>")
	)
	(segment
		(start 52.481226 -217.921078)
		(end 52.453032 -217.949272)
		(width 0.16002)
		(layer "In2.Cu")
		(net "M_B_CPU1_SB_DQS_DP<6>")
	)
	(segment
		(start 58.473086 -218.711018)
		(end 58.473086 -218.727274)
		(width 0.16002)
		(layer "In2.Cu")
		(net "M_B_CPU1_SB_DQS_DP<6>")
	)
	(segment
		(start 54.37632 -217.987372)
		(end 54.348126 -217.959178)
		(width 0.16002)
		(layer "In2.Cu")
		(net "M_B_CPU1_SB_DQS_DP<6>")
	)
	(segment
		(start 54.733698 -218.34475)
		(end 54.620414 -218.231466)
		(width 0.18288)
		(layer "In2.Cu")
		(net "M_B_CPU1_SB_DQS_DP<6>")
	)
	(segment
		(start 52.621434 -217.78087)
		(end 52.481226 -217.921078)
		(width 0.18288)
		(layer "In2.Cu")
		(net "M_B_CPU1_SB_DQS_DP<6>")
	)
	(segment
		(start 63.873888 -217.353134)
		(end 63.85814 -217.353134)
		(width 0.16002)
		(layer "In2.Cu")
		(net "M_B_CPU1_SB_DQS_DP<6>")
	)
	(segment
		(start 59.973972 -218.00312)
		(end 59.77382 -218.203272)
		(width 0.16002)
		(layer "In2.Cu")
		(net "M_B_CPU1_SB_DQS_DP<6>")
	)
	(segment
		(start 88.427814 -232.038906)
		(end 88.4174 -232.03281)
		(width 0.088646)
		(layer "In2.Cu")
		(net "M_B_CPU1_SB_DQS_DP<6>")
	)
	(segment
		(start 52.25288 -218.165172)
		(end 52.237132 -218.165172)
		(width 0.16002)
		(layer "In2.Cu")
		(net "M_B_CPU1_SB_DQS_DP<6>")
	)
	(segment
		(start 64.102234 -217.10904)
		(end 64.07404 -217.137234)
		(width 0.16002)
		(layer "In2.Cu")
		(net "M_B_CPU1_SB_DQS_DP<6>")
	)
	(segment
		(start 62.11824 -218.175332)
		(end 62.102492 -218.175332)
		(width 0.16002)
		(layer "In2.Cu")
		(net "M_B_CPU1_SB_DQS_DP<6>")
	)
	(segment
		(start 54.620414 -218.231466)
		(end 54.59222 -218.203272)
		(width 0.16002)
		(layer "In2.Cu")
		(net "M_B_CPU1_SB_DQS_DP<6>")
	)
	(segment
		(start 58.273442 -218.926918)
		(end 58.257186 -218.926918)
		(width 0.16002)
		(layer "In2.Cu")
		(net "M_B_CPU1_SB_DQS_DP<6>")
	)
	(segment
		(start 52.237132 -218.165172)
		(end 52.208938 -218.193366)
		(width 0.16002)
		(layer "In2.Cu")
		(net "M_B_CPU1_SB_DQS_DP<6>")
	)
	(segment
		(start 63.618618 -217.592656)
		(end 63.162942 -217.592656)
		(width 0.18288)
		(layer "In2.Cu")
		(net "M_B_CPU1_SB_DQS_DP<6>")
	)
	(arc
		(start 86.548468 -232.038906)
		(mid 86.265766 -231.96313)
		(end 85.983064 -232.038906)
		(width 0.088646)
		(layer "In2.Cu")
		(net "M_B_CPU1_SB_DQS_DP<6>")
	)
	(arc
		(start 87.488268 -232.038906)
		(mid 87.205566 -231.96313)
		(end 86.922864 -232.038906)
		(width 0.088646)
		(layer "In2.Cu")
		(net "M_B_CPU1_SB_DQS_DP<6>")
	)
	(arc
		(start 86.922864 -232.038906)
		(mid 86.735666 -232.089049)
		(end 86.548468 -232.038906)
		(width 0.088646)
		(layer "In2.Cu")
		(net "M_B_CPU1_SB_DQS_DP<6>")
	)
	(arc
		(start 85.608668 -232.038906)
		(mid 85.334469 -231.963071)
		(end 85.057996 -232.03027)
		(width 0.088646)
		(layer "In2.Cu")
		(net "M_B_CPU1_SB_DQS_DP<6>")
	)
	(arc
		(start 88.4174 -232.03281)
		(mid 88.139222 -231.963087)
		(end 87.862664 -232.038906)
		(width 0.088646)
		(layer "In2.Cu")
		(net "M_B_CPU1_SB_DQS_DP<6>")
	)
	(arc
		(start 89.74201 -232.038906)
		(mid 89.554812 -232.089049)
		(end 89.367614 -232.038906)
		(width 0.088646)
		(layer "In2.Cu")
		(net "M_B_CPU1_SB_DQS_DP<6>")
	)
	(arc
		(start 85.983064 -232.038906)
		(mid 85.795866 -232.089049)
		(end 85.608668 -232.038906)
		(width 0.088646)
		(layer "In2.Cu")
		(net "M_B_CPU1_SB_DQS_DP<6>")
	)
	(arc
		(start 90.583512 -232.44175)
		(mid 90.268982 -232.018529)
		(end 89.74201 -232.038906)
		(width 0.088646)
		(layer "In2.Cu")
		(net "M_B_CPU1_SB_DQS_DP<6>")
	)
	(arc
		(start 90.586306 -232.462578)
		(mid 90.585005 -232.452151)
		(end 90.583512 -232.44175)
		(width 0.088646)
		(layer "In2.Cu")
		(net "M_B_CPU1_SB_DQS_DP<6>")
	)
	(arc
		(start 84.668614 -232.039414)
		(mid 84.532542 -231.982656)
		(end 84.38642 -231.96296)
		(width 0.088646)
		(layer "In2.Cu")
		(net "M_B_CPU1_SB_DQS_DP<6>")
	)
	(arc
		(start 89.352882 -232.03027)
		(mid 89.076407 -231.96295)
		(end 88.80221 -232.038906)
		(width 0.088646)
		(layer "In2.Cu")
		(net "M_B_CPU1_SB_DQS_DP<6>")
	)
	(arc
		(start 88.80221 -232.038906)
		(mid 88.615012 -232.089049)
		(end 88.427814 -232.038906)
		(width 0.088646)
		(layer "In2.Cu")
		(net "M_B_CPU1_SB_DQS_DP<6>")
	)
	(arc
		(start 87.862664 -232.038906)
		(mid 87.675466 -232.089049)
		(end 87.488268 -232.038906)
		(width 0.088646)
		(layer "In2.Cu")
		(net "M_B_CPU1_SB_DQS_DP<6>")
	)
	(arc
		(start 85.043264 -232.038906)
		(mid 84.856066 -232.089049)
		(end 84.668868 -232.038906)
		(width 0.088646)
		(layer "In2.Cu")
		(net "M_B_CPU1_SB_DQS_DP<6>")
	)
	(segment
		(start 43.908218 -226.905566)
		(end 43.485816 -227.327968)
		(width 0.20066)
		(layer "F.Cu")
		(net "M_B_CPU1_SB_DQS_DP<5>")
	)
	(segment
		(start 49.959514 -227.066602)
		(end 49.469802 -227.066602)
		(width 0.20066)
		(layer "F.Cu")
		(net "M_B_CPU1_SB_DQS_DP<5>")
	)
	(segment
		(start 47.060358 -226.641914)
		(end 47.060104 -226.64166)
		(width 0.1016)
		(layer "F.Cu")
		(net "M_B_CPU1_SB_DQS_DP<5>")
	)
	(segment
		(start 48.603916 -227.327968)
		(end 47.9679 -226.903026)
		(width 0.20066)
		(layer "F.Cu")
		(net "M_B_CPU1_SB_DQS_DP<5>")
	)
	(segment
		(start 94.254066 -235.506006)
		(end 94.254066 -234.97032)
		(width 0.20066)
		(layer "F.Cu")
		(net "M_B_CPU1_SB_DQS_DP<5>")
	)
	(segment
		(start 94.254066 -234.97032)
		(end 94.253812 -234.970066)
		(width 0.20066)
		(layer "F.Cu")
		(net "M_B_CPU1_SB_DQS_DP<5>")
	)
	(segment
		(start 43.485816 -227.327968)
		(end 43.151552 -227.327968)
		(width 0.20066)
		(layer "F.Cu")
		(net "M_B_CPU1_SB_DQS_DP<5>")
	)
	(segment
		(start 43.151552 -227.327968)
		(end 42.890186 -227.066602)
		(width 0.20066)
		(layer "F.Cu")
		(net "M_B_CPU1_SB_DQS_DP<5>")
	)
	(segment
		(start 47.201836 -226.641914)
		(end 47.060358 -226.641914)
		(width 0.20066)
		(layer "F.Cu")
		(net "M_B_CPU1_SB_DQS_DP<5>")
	)
	(segment
		(start 44.735242 -226.636072)
		(end 44.537884 -226.636072)
		(width 0.20066)
		(layer "F.Cu")
		(net "M_B_CPU1_SB_DQS_DP<5>")
	)
	(segment
		(start 44.98213 -226.64166)
		(end 44.74083 -226.64166)
		(width 0.101854)
		(layer "F.Cu")
		(net "M_B_CPU1_SB_DQS_DP<5>")
	)
	(segment
		(start 49.469802 -227.066602)
		(end 49.208436 -227.327968)
		(width 0.20066)
		(layer "F.Cu")
		(net "M_B_CPU1_SB_DQS_DP<5>")
	)
	(segment
		(start 49.208436 -227.327968)
		(end 48.603916 -227.327968)
		(width 0.20066)
		(layer "F.Cu")
		(net "M_B_CPU1_SB_DQS_DP<5>")
	)
	(segment
		(start 47.9679 -226.903026)
		(end 47.462948 -226.903026)
		(width 0.20066)
		(layer "F.Cu")
		(net "M_B_CPU1_SB_DQS_DP<5>")
	)
	(segment
		(start 44.537884 -226.636072)
		(end 44.26839 -226.905566)
		(width 0.20066)
		(layer "F.Cu")
		(net "M_B_CPU1_SB_DQS_DP<5>")
	)
	(segment
		(start 42.890186 -227.066602)
		(end 42.415714 -227.066602)
		(width 0.20066)
		(layer "F.Cu")
		(net "M_B_CPU1_SB_DQS_DP<5>")
	)
	(segment
		(start 44.74083 -226.64166)
		(end 44.735242 -226.636072)
		(width 0.101854)
		(layer "F.Cu")
		(net "M_B_CPU1_SB_DQS_DP<5>")
	)
	(segment
		(start 44.26839 -226.905566)
		(end 43.908218 -226.905566)
		(width 0.20066)
		(layer "F.Cu")
		(net "M_B_CPU1_SB_DQS_DP<5>")
	)
	(segment
		(start 47.060104 -226.64166)
		(end 44.98213 -226.64166)
		(width 0.1016)
		(layer "F.Cu")
		(net "M_B_CPU1_SB_DQS_DP<5>")
	)
	(segment
		(start 51.064414 -227.066602)
		(end 49.959514 -227.066602)
		(width 0.20066)
		(layer "F.Cu")
		(net "M_B_CPU1_SB_DQS_DP<5>")
	)
	(segment
		(start 47.462948 -226.903026)
		(end 47.201836 -226.641914)
		(width 0.20066)
		(layer "F.Cu")
		(net "M_B_CPU1_SB_DQS_DP<5>")
	)
	(segment
		(start 85.527896 -234.471972)
		(end 85.513164 -234.480608)
		(width 0.088646)
		(layer "In4.Cu")
		(net "M_B_CPU1_SB_DQS_DP<5>")
	)
	(segment
		(start 66.632582 -226.941888)
		(end 66.335402 -226.644708)
		(width 0.18288)
		(layer "In4.Cu")
		(net "M_B_CPU1_SB_DQS_DP<5>")
	)
	(segment
		(start 83.751166 -234.531154)
		(end 83.615022 -234.667298)
		(width 0.088646)
		(layer "In4.Cu")
		(net "M_B_CPU1_SB_DQS_DP<5>")
	)
	(segment
		(start 93.941138 -234.970066)
		(end 93.875606 -234.904534)
		(width 0.088646)
		(layer "In4.Cu")
		(net "M_B_CPU1_SB_DQS_DP<5>")
	)
	(segment
		(start 59.315858 -224.570798)
		(end 58.681366 -225.20529)
		(width 0.18288)
		(layer "In4.Cu")
		(net "M_B_CPU1_SB_DQS_DP<5>")
	)
	(segment
		(start 65.677796 -226.923854)
		(end 65.169034 -226.923854)
		(width 0.18288)
		(layer "In4.Cu")
		(net "M_B_CPU1_SB_DQS_DP<5>")
	)
	(segment
		(start 82.708496 -234.42295)
		(end 75.146154 -234.42295)
		(width 0.18288)
		(layer "In4.Cu")
		(net "M_B_CPU1_SB_DQS_DP<5>")
	)
	(segment
		(start 83.615022 -234.667298)
		(end 83.348576 -234.667298)
		(width 0.088646)
		(layer "In4.Cu")
		(net "M_B_CPU1_SB_DQS_DP<5>")
	)
	(segment
		(start 53.786786 -226.311206)
		(end 52.583334 -227.514658)
		(width 0.18288)
		(layer "In4.Cu")
		(net "M_B_CPU1_SB_DQS_DP<5>")
	)
	(segment
		(start 83.348576 -234.667298)
		(end 83.163918 -234.48264)
		(width 0.088646)
		(layer "In4.Cu")
		(net "M_B_CPU1_SB_DQS_DP<5>")
	)
	(segment
		(start 82.812636 -234.48264)
		(end 82.752946 -234.42295)
		(width 0.088646)
		(layer "In4.Cu")
		(net "M_B_CPU1_SB_DQS_DP<5>")
	)
	(segment
		(start 75.146154 -234.42295)
		(end 67.665092 -226.941888)
		(width 0.18288)
		(layer "In4.Cu")
		(net "M_B_CPU1_SB_DQS_DP<5>")
	)
	(segment
		(start 66.335402 -226.644708)
		(end 65.956942 -226.644708)
		(width 0.18288)
		(layer "In4.Cu")
		(net "M_B_CPU1_SB_DQS_DP<5>")
	)
	(segment
		(start 60.35421 -224.570798)
		(end 59.315858 -224.570798)
		(width 0.18288)
		(layer "In4.Cu")
		(net "M_B_CPU1_SB_DQS_DP<5>")
	)
	(segment
		(start 60.997084 -225.213672)
		(end 60.35421 -224.570798)
		(width 0.18288)
		(layer "In4.Cu")
		(net "M_B_CPU1_SB_DQS_DP<5>")
	)
	(segment
		(start 94.253812 -234.970066)
		(end 93.941138 -234.970066)
		(width 0.088646)
		(layer "In4.Cu")
		(net "M_B_CPU1_SB_DQS_DP<5>")
	)
	(segment
		(start 86.467696 -234.471972)
		(end 86.452964 -234.480608)
		(width 0.088646)
		(layer "In4.Cu")
		(net "M_B_CPU1_SB_DQS_DP<5>")
	)
	(segment
		(start 61.856112 -224.941638)
		(end 61.587634 -225.210116)
		(width 0.18288)
		(layer "In4.Cu")
		(net "M_B_CPU1_SB_DQS_DP<5>")
	)
	(segment
		(start 67.665092 -226.941888)
		(end 66.632582 -226.941888)
		(width 0.18288)
		(layer "In4.Cu")
		(net "M_B_CPU1_SB_DQS_DP<5>")
	)
	(segment
		(start 91.166696 -234.471972)
		(end 91.151964 -234.480608)
		(width 0.088646)
		(layer "In4.Cu")
		(net "M_B_CPU1_SB_DQS_DP<5>")
	)
	(segment
		(start 87.407496 -234.471972)
		(end 87.392764 -234.480608)
		(width 0.088646)
		(layer "In4.Cu")
		(net "M_B_CPU1_SB_DQS_DP<5>")
	)
	(segment
		(start 58.681366 -225.20529)
		(end 58.094372 -225.20529)
		(width 0.18288)
		(layer "In4.Cu")
		(net "M_B_CPU1_SB_DQS_DP<5>")
	)
	(segment
		(start 56.182514 -226.699318)
		(end 55.794402 -226.311206)
		(width 0.18288)
		(layer "In4.Cu")
		(net "M_B_CPU1_SB_DQS_DP<5>")
	)
	(segment
		(start 83.163918 -234.48264)
		(end 82.812636 -234.48264)
		(width 0.088646)
		(layer "In4.Cu")
		(net "M_B_CPU1_SB_DQS_DP<5>")
	)
	(segment
		(start 82.752946 -234.42295)
		(end 82.708496 -234.42295)
		(width 0.088646)
		(layer "In4.Cu")
		(net "M_B_CPU1_SB_DQS_DP<5>")
	)
	(segment
		(start 64.89319 -226.64801)
		(end 64.89319 -226.051872)
		(width 0.18288)
		(layer "In4.Cu")
		(net "M_B_CPU1_SB_DQS_DP<5>")
	)
	(segment
		(start 62.244478 -224.941638)
		(end 61.856112 -224.941638)
		(width 0.18288)
		(layer "In4.Cu")
		(net "M_B_CPU1_SB_DQS_DP<5>")
	)
	(segment
		(start 84.386166 -234.531154)
		(end 83.751166 -234.531154)
		(width 0.088646)
		(layer "In4.Cu")
		(net "M_B_CPU1_SB_DQS_DP<5>")
	)
	(segment
		(start 61.57849 -225.213672)
		(end 60.997084 -225.213672)
		(width 0.18288)
		(layer "In4.Cu")
		(net "M_B_CPU1_SB_DQS_DP<5>")
	)
	(segment
		(start 65.169034 -226.923854)
		(end 64.89319 -226.64801)
		(width 0.18288)
		(layer "In4.Cu")
		(net "M_B_CPU1_SB_DQS_DP<5>")
	)
	(segment
		(start 93.046296 -234.471972)
		(end 93.031564 -234.480608)
		(width 0.088646)
		(layer "In4.Cu")
		(net "M_B_CPU1_SB_DQS_DP<5>")
	)
	(segment
		(start 61.582046 -225.210116)
		(end 61.57849 -225.213672)
		(width 0.18288)
		(layer "In4.Cu")
		(net "M_B_CPU1_SB_DQS_DP<5>")
	)
	(segment
		(start 58.094372 -225.20529)
		(end 56.600344 -226.699318)
		(width 0.18288)
		(layer "In4.Cu")
		(net "M_B_CPU1_SB_DQS_DP<5>")
	)
	(segment
		(start 62.515242 -225.212402)
		(end 62.244478 -224.941638)
		(width 0.18288)
		(layer "In4.Cu")
		(net "M_B_CPU1_SB_DQS_DP<5>")
	)
	(segment
		(start 89.287096 -234.471972)
		(end 89.272364 -234.480608)
		(width 0.088646)
		(layer "In4.Cu")
		(net "M_B_CPU1_SB_DQS_DP<5>")
	)
	(segment
		(start 55.794402 -226.311206)
		(end 53.786786 -226.311206)
		(width 0.18288)
		(layer "In4.Cu")
		(net "M_B_CPU1_SB_DQS_DP<5>")
	)
	(segment
		(start 56.600344 -226.699318)
		(end 56.182514 -226.699318)
		(width 0.18288)
		(layer "In4.Cu")
		(net "M_B_CPU1_SB_DQS_DP<5>")
	)
	(segment
		(start 88.347296 -234.471972)
		(end 88.332564 -234.480608)
		(width 0.088646)
		(layer "In4.Cu")
		(net "M_B_CPU1_SB_DQS_DP<5>")
	)
	(segment
		(start 65.956942 -226.644708)
		(end 65.677796 -226.923854)
		(width 0.18288)
		(layer "In4.Cu")
		(net "M_B_CPU1_SB_DQS_DP<5>")
	)
	(segment
		(start 51.51247 -227.514658)
		(end 51.064414 -227.066602)
		(width 0.18288)
		(layer "In4.Cu")
		(net "M_B_CPU1_SB_DQS_DP<5>")
	)
	(segment
		(start 61.587634 -225.210116)
		(end 61.582046 -225.210116)
		(width 0.18288)
		(layer "In4.Cu")
		(net "M_B_CPU1_SB_DQS_DP<5>")
	)
	(segment
		(start 64.89319 -226.051872)
		(end 64.05372 -225.212402)
		(width 0.18288)
		(layer "In4.Cu")
		(net "M_B_CPU1_SB_DQS_DP<5>")
	)
	(segment
		(start 52.583334 -227.514658)
		(end 51.51247 -227.514658)
		(width 0.18288)
		(layer "In4.Cu")
		(net "M_B_CPU1_SB_DQS_DP<5>")
	)
	(segment
		(start 92.106496 -234.471972)
		(end 92.091764 -234.480608)
		(width 0.088646)
		(layer "In4.Cu")
		(net "M_B_CPU1_SB_DQS_DP<5>")
	)
	(segment
		(start 64.05372 -225.212402)
		(end 62.515242 -225.212402)
		(width 0.18288)
		(layer "In4.Cu")
		(net "M_B_CPU1_SB_DQS_DP<5>")
	)
	(arc
		(start 91.717368 -234.480608)
		(mid 91.443169 -234.404773)
		(end 91.166696 -234.471972)
		(width 0.088646)
		(layer "In4.Cu")
		(net "M_B_CPU1_SB_DQS_DP<5>")
	)
	(arc
		(start 84.573618 -234.480862)
		(mid 84.483199 -234.518321)
		(end 84.386166 -234.531154)
		(width 0.088646)
		(layer "In4.Cu")
		(net "M_B_CPU1_SB_DQS_DP<5>")
	)
	(arc
		(start 93.875606 -234.904534)
		(mid 93.874308 -234.89398)
		(end 93.872812 -234.883452)
		(width 0.088646)
		(layer "In4.Cu")
		(net "M_B_CPU1_SB_DQS_DP<5>")
	)
	(arc
		(start 90.212164 -234.480608)
		(mid 90.024966 -234.530751)
		(end 89.837768 -234.480608)
		(width 0.088646)
		(layer "In4.Cu")
		(net "M_B_CPU1_SB_DQS_DP<5>")
	)
	(arc
		(start 87.018368 -234.480608)
		(mid 86.744169 -234.404773)
		(end 86.467696 -234.471972)
		(width 0.088646)
		(layer "In4.Cu")
		(net "M_B_CPU1_SB_DQS_DP<5>")
	)
	(arc
		(start 92.091764 -234.480608)
		(mid 91.904566 -234.530751)
		(end 91.717368 -234.480608)
		(width 0.088646)
		(layer "In4.Cu")
		(net "M_B_CPU1_SB_DQS_DP<5>")
	)
	(arc
		(start 93.872812 -234.883452)
		(mid 93.566025 -234.463856)
		(end 93.046296 -234.471972)
		(width 0.088646)
		(layer "In4.Cu")
		(net "M_B_CPU1_SB_DQS_DP<5>")
	)
	(arc
		(start 91.151964 -234.480608)
		(mid 90.964766 -234.530751)
		(end 90.777568 -234.480608)
		(width 0.088646)
		(layer "In4.Cu")
		(net "M_B_CPU1_SB_DQS_DP<5>")
	)
	(arc
		(start 90.777568 -234.480608)
		(mid 90.494866 -234.404832)
		(end 90.212164 -234.480608)
		(width 0.088646)
		(layer "In4.Cu")
		(net "M_B_CPU1_SB_DQS_DP<5>")
	)
	(arc
		(start 85.513164 -234.480608)
		(mid 85.325966 -234.530751)
		(end 85.138768 -234.480608)
		(width 0.088646)
		(layer "In4.Cu")
		(net "M_B_CPU1_SB_DQS_DP<5>")
	)
	(arc
		(start 92.657168 -234.480608)
		(mid 92.382969 -234.404773)
		(end 92.106496 -234.471972)
		(width 0.088646)
		(layer "In4.Cu")
		(net "M_B_CPU1_SB_DQS_DP<5>")
	)
	(arc
		(start 89.837768 -234.480608)
		(mid 89.563569 -234.404773)
		(end 89.287096 -234.471972)
		(width 0.088646)
		(layer "In4.Cu")
		(net "M_B_CPU1_SB_DQS_DP<5>")
	)
	(arc
		(start 88.897968 -234.480608)
		(mid 88.623769 -234.404773)
		(end 88.347296 -234.471972)
		(width 0.088646)
		(layer "In4.Cu")
		(net "M_B_CPU1_SB_DQS_DP<5>")
	)
	(arc
		(start 87.392764 -234.480608)
		(mid 87.205566 -234.530751)
		(end 87.018368 -234.480608)
		(width 0.088646)
		(layer "In4.Cu")
		(net "M_B_CPU1_SB_DQS_DP<5>")
	)
	(arc
		(start 88.332564 -234.480608)
		(mid 88.145366 -234.530751)
		(end 87.958168 -234.480608)
		(width 0.088646)
		(layer "In4.Cu")
		(net "M_B_CPU1_SB_DQS_DP<5>")
	)
	(arc
		(start 84.588096 -234.471972)
		(mid 84.580908 -234.4765)
		(end 84.573618 -234.480862)
		(width 0.088646)
		(layer "In4.Cu")
		(net "M_B_CPU1_SB_DQS_DP<5>")
	)
	(arc
		(start 86.452964 -234.480608)
		(mid 86.265766 -234.530751)
		(end 86.078568 -234.480608)
		(width 0.088646)
		(layer "In4.Cu")
		(net "M_B_CPU1_SB_DQS_DP<5>")
	)
	(arc
		(start 89.272364 -234.480608)
		(mid 89.085166 -234.530751)
		(end 88.897968 -234.480608)
		(width 0.088646)
		(layer "In4.Cu")
		(net "M_B_CPU1_SB_DQS_DP<5>")
	)
	(arc
		(start 93.031564 -234.480608)
		(mid 92.844366 -234.530751)
		(end 92.657168 -234.480608)
		(width 0.088646)
		(layer "In4.Cu")
		(net "M_B_CPU1_SB_DQS_DP<5>")
	)
	(arc
		(start 86.078568 -234.480608)
		(mid 85.804369 -234.404773)
		(end 85.527896 -234.471972)
		(width 0.088646)
		(layer "In4.Cu")
		(net "M_B_CPU1_SB_DQS_DP<5>")
	)
	(arc
		(start 85.138768 -234.480608)
		(mid 84.864569 -234.404773)
		(end 84.588096 -234.471972)
		(width 0.088646)
		(layer "In4.Cu")
		(net "M_B_CPU1_SB_DQS_DP<5>")
	)
	(arc
		(start 87.958168 -234.480608)
		(mid 87.683969 -234.404773)
		(end 87.407496 -234.471972)
		(width 0.088646)
		(layer "In4.Cu")
		(net "M_B_CPU1_SB_DQS_DP<5>")
	)
	(segment
		(start 51.064414 -236.416596)
		(end 49.959514 -236.416596)
		(width 0.20066)
		(layer "F.Cu")
		(net "M_B_CPU1_SB_DQS_DP<4>")
	)
	(segment
		(start 42.890186 -236.416596)
		(end 42.415714 -236.416596)
		(width 0.20066)
		(layer "F.Cu")
		(net "M_B_CPU1_SB_DQS_DP<4>")
	)
	(segment
		(start 49.959514 -236.416596)
		(end 49.469802 -236.416596)
		(width 0.20066)
		(layer "F.Cu")
		(net "M_B_CPU1_SB_DQS_DP<4>")
	)
	(segment
		(start 48.603916 -236.677962)
		(end 47.9679 -236.25302)
		(width 0.20066)
		(layer "F.Cu")
		(net "M_B_CPU1_SB_DQS_DP<4>")
	)
	(segment
		(start 90.024712 -242.830858)
		(end 90.024712 -242.295172)
		(width 0.20066)
		(layer "F.Cu")
		(net "M_B_CPU1_SB_DQS_DP<4>")
	)
	(segment
		(start 49.208436 -236.677962)
		(end 48.603916 -236.677962)
		(width 0.20066)
		(layer "F.Cu")
		(net "M_B_CPU1_SB_DQS_DP<4>")
	)
	(segment
		(start 90.024712 -242.295172)
		(end 90.024966 -242.294918)
		(width 0.20066)
		(layer "F.Cu")
		(net "M_B_CPU1_SB_DQS_DP<4>")
	)
	(segment
		(start 47.060104 -235.991654)
		(end 44.98213 -235.991654)
		(width 0.1016)
		(layer "F.Cu")
		(net "M_B_CPU1_SB_DQS_DP<4>")
	)
	(segment
		(start 47.060358 -235.991908)
		(end 47.060104 -235.991654)
		(width 0.1016)
		(layer "F.Cu")
		(net "M_B_CPU1_SB_DQS_DP<4>")
	)
	(segment
		(start 44.26839 -236.25556)
		(end 43.908218 -236.25556)
		(width 0.20066)
		(layer "F.Cu")
		(net "M_B_CPU1_SB_DQS_DP<4>")
	)
	(segment
		(start 49.469802 -236.416596)
		(end 49.208436 -236.677962)
		(width 0.20066)
		(layer "F.Cu")
		(net "M_B_CPU1_SB_DQS_DP<4>")
	)
	(segment
		(start 44.735242 -235.986066)
		(end 44.537884 -235.986066)
		(width 0.20066)
		(layer "F.Cu")
		(net "M_B_CPU1_SB_DQS_DP<4>")
	)
	(segment
		(start 44.74083 -235.991654)
		(end 44.735242 -235.986066)
		(width 0.101854)
		(layer "F.Cu")
		(net "M_B_CPU1_SB_DQS_DP<4>")
	)
	(segment
		(start 47.462948 -236.25302)
		(end 47.201836 -235.991908)
		(width 0.20066)
		(layer "F.Cu")
		(net "M_B_CPU1_SB_DQS_DP<4>")
	)
	(segment
		(start 43.485816 -236.677962)
		(end 43.151552 -236.677962)
		(width 0.20066)
		(layer "F.Cu")
		(net "M_B_CPU1_SB_DQS_DP<4>")
	)
	(segment
		(start 43.151552 -236.677962)
		(end 42.890186 -236.416596)
		(width 0.20066)
		(layer "F.Cu")
		(net "M_B_CPU1_SB_DQS_DP<4>")
	)
	(segment
		(start 44.98213 -235.991654)
		(end 44.74083 -235.991654)
		(width 0.101854)
		(layer "F.Cu")
		(net "M_B_CPU1_SB_DQS_DP<4>")
	)
	(segment
		(start 47.201836 -235.991908)
		(end 47.060358 -235.991908)
		(width 0.20066)
		(layer "F.Cu")
		(net "M_B_CPU1_SB_DQS_DP<4>")
	)
	(segment
		(start 47.9679 -236.25302)
		(end 47.462948 -236.25302)
		(width 0.20066)
		(layer "F.Cu")
		(net "M_B_CPU1_SB_DQS_DP<4>")
	)
	(segment
		(start 44.537884 -235.986066)
		(end 44.26839 -236.25556)
		(width 0.20066)
		(layer "F.Cu")
		(net "M_B_CPU1_SB_DQS_DP<4>")
	)
	(segment
		(start 43.908218 -236.25556)
		(end 43.485816 -236.677962)
		(width 0.20066)
		(layer "F.Cu")
		(net "M_B_CPU1_SB_DQS_DP<4>")
	)
	(segment
		(start 58.228992 -237.6551)
		(end 58.155078 -237.729014)
		(width 0.18288)
		(layer "In2.Cu")
		(net "M_B_CPU1_SB_DQS_DP<4>")
	)
	(segment
		(start 66.016886 -237.427262)
		(end 65.817242 -237.626906)
		(width 0.16002)
		(layer "In2.Cu")
		(net "M_B_CPU1_SB_DQS_DP<4>")
	)
	(segment
		(start 60.007754 -238.307626)
		(end 60.007754 -238.29137)
		(width 0.16002)
		(layer "In2.Cu")
		(net "M_B_CPU1_SB_DQS_DP<4>")
	)
	(segment
		(start 86.45271 -242.619276)
		(end 86.438232 -242.627658)
		(width 0.088646)
		(layer "In2.Cu")
		(net "M_B_CPU1_SB_DQS_DP<4>")
	)
	(segment
		(start 56.533542 -237.411006)
		(end 56.505348 -237.382812)
		(width 0.16002)
		(layer "In2.Cu")
		(net "M_B_CPU1_SB_DQS_DP<4>")
	)
	(segment
		(start 84.56803 -242.622324)
		(end 84.554822 -242.62969)
		(width 0.088646)
		(layer "In2.Cu")
		(net "M_B_CPU1_SB_DQS_DP<4>")
	)
	(segment
		(start 66.016886 -237.411006)
		(end 66.016886 -237.427262)
		(width 0.16002)
		(layer "In2.Cu")
		(net "M_B_CPU1_SB_DQS_DP<4>")
	)
	(segment
		(start 71.073264 -239.178592)
		(end 71.005954 -239.015778)
		(width 0.18288)
		(layer "In2.Cu")
		(net "M_B_CPU1_SB_DQS_DP<4>")
	)
	(segment
		(start 88.332564 -242.619276)
		(end 88.324182 -242.624102)
		(width 0.088646)
		(layer "In2.Cu")
		(net "M_B_CPU1_SB_DQS_DP<4>")
	)
	(segment
		(start 58.473086 -237.427262)
		(end 58.273442 -237.626906)
		(width 0.16002)
		(layer "In2.Cu")
		(net "M_B_CPU1_SB_DQS_DP<4>")
	)
	(segment
		(start 71.005954 -239.015778)
		(end 70.498716 -238.805974)
		(width 0.18288)
		(layer "In2.Cu")
		(net "M_B_CPU1_SB_DQS_DP<4>")
	)
	(segment
		(start 60.007754 -238.29137)
		(end 59.97956 -238.263176)
		(width 0.16002)
		(layer "In2.Cu")
		(net "M_B_CPU1_SB_DQS_DP<4>")
	)
	(segment
		(start 64.107822 -237.457742)
		(end 64.107822 -237.441486)
		(width 0.16002)
		(layer "In2.Cu")
		(net "M_B_CPU1_SB_DQS_DP<4>")
	)
	(segment
		(start 52.248562 -236.86643)
		(end 51.853338 -236.86643)
		(width 0.18288)
		(layer "In2.Cu")
		(net "M_B_CPU1_SB_DQS_DP<4>")
	)
	(segment
		(start 90.337894 -242.294918)
		(end 90.395044 -242.352068)
		(width 0.088646)
		(layer "In2.Cu")
		(net "M_B_CPU1_SB_DQS_DP<4>")
	)
	(segment
		(start 56.505348 -237.382812)
		(end 56.032146 -236.90961)
		(width 0.18288)
		(layer "In2.Cu")
		(net "M_B_CPU1_SB_DQS_DP<4>")
	)
	(segment
		(start 86.467442 -242.61064)
		(end 86.45271 -242.619276)
		(width 0.088646)
		(layer "In2.Cu")
		(net "M_B_CPU1_SB_DQS_DP<4>")
	)
	(segment
		(start 61.916818 -238.26089)
		(end 61.916818 -238.277146)
		(width 0.16002)
		(layer "In2.Cu")
		(net "M_B_CPU1_SB_DQS_DP<4>")
	)
	(segment
		(start 56.749442 -237.626906)
		(end 56.733186 -237.626906)
		(width 0.16002)
		(layer "In2.Cu")
		(net "M_B_CPU1_SB_DQS_DP<4>")
	)
	(segment
		(start 56.85155 -237.729014)
		(end 56.777636 -237.6551)
		(width 0.18288)
		(layer "In2.Cu")
		(net "M_B_CPU1_SB_DQS_DP<4>")
	)
	(segment
		(start 59.734958 -237.716822)
		(end 59.218322 -237.200186)
		(width 0.18288)
		(layer "In2.Cu")
		(net "M_B_CPU1_SB_DQS_DP<4>")
	)
	(segment
		(start 64.079628 -237.413292)
		(end 63.860426 -237.19409)
		(width 0.18288)
		(layer "In2.Cu")
		(net "M_B_CPU1_SB_DQS_DP<4>")
	)
	(segment
		(start 90.024966 -242.294918)
		(end 90.337894 -242.294918)
		(width 0.088646)
		(layer "In2.Cu")
		(net "M_B_CPU1_SB_DQS_DP<4>")
	)
	(segment
		(start 53.92801 -236.23651)
		(end 52.878482 -236.23651)
		(width 0.18288)
		(layer "In2.Cu")
		(net "M_B_CPU1_SB_DQS_DP<4>")
	)
	(segment
		(start 85.533484 -242.607084)
		(end 85.512656 -242.619276)
		(width 0.088646)
		(layer "In2.Cu")
		(net "M_B_CPU1_SB_DQS_DP<4>")
	)
	(segment
		(start 64.351916 -237.68558)
		(end 64.323722 -237.657386)
		(width 0.16002)
		(layer "In2.Cu")
		(net "M_B_CPU1_SB_DQS_DP<4>")
	)
	(segment
		(start 61.672724 -238.504984)
		(end 61.581538 -238.59617)
		(width 0.18288)
		(layer "In2.Cu")
		(net "M_B_CPU1_SB_DQS_DP<4>")
	)
	(segment
		(start 66.04508 -237.382812)
		(end 66.016886 -237.411006)
		(width 0.16002)
		(layer "In2.Cu")
		(net "M_B_CPU1_SB_DQS_DP<4>")
	)
	(segment
		(start 84.57311 -242.619276)
		(end 84.56803 -242.622324)
		(width 0.088646)
		(layer "In2.Cu")
		(net "M_B_CPU1_SB_DQS_DP<4>")
	)
	(segment
		(start 54.444392 -236.76864)
		(end 54.24424 -236.568488)
		(width 0.16002)
		(layer "In2.Cu")
		(net "M_B_CPU1_SB_DQS_DP<4>")
	)
	(segment
		(start 58.50128 -237.382812)
		(end 58.473086 -237.411006)
		(width 0.16002)
		(layer "In2.Cu")
		(net "M_B_CPU1_SB_DQS_DP<4>")
	)
	(segment
		(start 83.064096 -242.531646)
		(end 74.773028 -242.531646)
		(width 0.18288)
		(layer "In2.Cu")
		(net "M_B_CPU1_SB_DQS_DP<4>")
	)
	(segment
		(start 83.553046 -242.543076)
		(end 83.504532 -242.59159)
		(width 0.088646)
		(layer "In2.Cu")
		(net "M_B_CPU1_SB_DQS_DP<4>")
	)
	(segment
		(start 61.581538 -238.59617)
		(end 60.312554 -238.59617)
		(width 0.18288)
		(layer "In2.Cu")
		(net "M_B_CPU1_SB_DQS_DP<4>")
	)
	(segment
		(start 71.665084 -239.423702)
		(end 71.073264 -239.178592)
		(width 0.18288)
		(layer "In2.Cu")
		(net "M_B_CPU1_SB_DQS_DP<4>")
	)
	(segment
		(start 52.320698 -236.794294)
		(end 52.248562 -236.86643)
		(width 0.18288)
		(layer "In2.Cu")
		(net "M_B_CPU1_SB_DQS_DP<4>")
	)
	(segment
		(start 52.878482 -236.23651)
		(end 52.592986 -236.522006)
		(width 0.18288)
		(layer "In2.Cu")
		(net "M_B_CPU1_SB_DQS_DP<4>")
	)
	(segment
		(start 62.983618 -237.19409)
		(end 61.945012 -238.232696)
		(width 0.18288)
		(layer "In2.Cu")
		(net "M_B_CPU1_SB_DQS_DP<4>")
	)
	(segment
		(start 64.323722 -237.657386)
		(end 64.307466 -237.657386)
		(width 0.16002)
		(layer "In2.Cu")
		(net "M_B_CPU1_SB_DQS_DP<4>")
	)
	(segment
		(start 54.24424 -236.55274)
		(end 54.216046 -236.524546)
		(width 0.16002)
		(layer "In2.Cu")
		(net "M_B_CPU1_SB_DQS_DP<4>")
	)
	(segment
		(start 52.36464 -236.7661)
		(end 52.348892 -236.7661)
		(width 0.16002)
		(layer "In2.Cu")
		(net "M_B_CPU1_SB_DQS_DP<4>")
	)
	(segment
		(start 60.251848 -238.535464)
		(end 60.223654 -238.50727)
		(width 0.16002)
		(layer "In2.Cu")
		(net "M_B_CPU1_SB_DQS_DP<4>")
	)
	(segment
		(start 58.473086 -237.411006)
		(end 58.473086 -237.427262)
		(width 0.16002)
		(layer "In2.Cu")
		(net "M_B_CPU1_SB_DQS_DP<4>")
	)
	(segment
		(start 66.653156 -237.15345)
		(end 66.273934 -237.15345)
		(width 0.18288)
		(layer "In2.Cu")
		(net "M_B_CPU1_SB_DQS_DP<4>")
	)
	(segment
		(start 63.860426 -237.19409)
		(end 62.983618 -237.19409)
		(width 0.18288)
		(layer "In2.Cu")
		(net "M_B_CPU1_SB_DQS_DP<4>")
	)
	(segment
		(start 60.312554 -238.59617)
		(end 60.251848 -238.535464)
		(width 0.18288)
		(layer "In2.Cu")
		(net "M_B_CPU1_SB_DQS_DP<4>")
	)
	(segment
		(start 61.916818 -238.277146)
		(end 61.717174 -238.47679)
		(width 0.16002)
		(layer "In2.Cu")
		(net "M_B_CPU1_SB_DQS_DP<4>")
	)
	(segment
		(start 54.46014 -236.76864)
		(end 54.444392 -236.76864)
		(width 0.16002)
		(layer "In2.Cu")
		(net "M_B_CPU1_SB_DQS_DP<4>")
	)
	(segment
		(start 60.207398 -238.50727)
		(end 60.007754 -238.307626)
		(width 0.16002)
		(layer "In2.Cu")
		(net "M_B_CPU1_SB_DQS_DP<4>")
	)
	(segment
		(start 88.347296 -242.61064)
		(end 88.332564 -242.619276)
		(width 0.088646)
		(layer "In2.Cu")
		(net "M_B_CPU1_SB_DQS_DP<4>")
	)
	(segment
		(start 56.032146 -236.90961)
		(end 54.60111 -236.90961)
		(width 0.18288)
		(layer "In2.Cu")
		(net "M_B_CPU1_SB_DQS_DP<4>")
	)
	(segment
		(start 67.418712 -237.665006)
		(end 66.653156 -237.15345)
		(width 0.18288)
		(layer "In2.Cu")
		(net "M_B_CPU1_SB_DQS_DP<4>")
	)
	(segment
		(start 52.564792 -236.565948)
		(end 52.36464 -236.7661)
		(width 0.16002)
		(layer "In2.Cu")
		(net "M_B_CPU1_SB_DQS_DP<4>")
	)
	(segment
		(start 52.592986 -236.522006)
		(end 52.564792 -236.5502)
		(width 0.16002)
		(layer "In2.Cu")
		(net "M_B_CPU1_SB_DQS_DP<4>")
	)
	(segment
		(start 52.348892 -236.7661)
		(end 52.320698 -236.794294)
		(width 0.16002)
		(layer "In2.Cu")
		(net "M_B_CPU1_SB_DQS_DP<4>")
	)
	(segment
		(start 54.488334 -236.796834)
		(end 54.46014 -236.76864)
		(width 0.16002)
		(layer "In2.Cu")
		(net "M_B_CPU1_SB_DQS_DP<4>")
	)
	(segment
		(start 59.218322 -237.200186)
		(end 58.683906 -237.200186)
		(width 0.18288)
		(layer "In2.Cu")
		(net "M_B_CPU1_SB_DQS_DP<4>")
	)
	(segment
		(start 70.336156 -238.873284)
		(end 69.829426 -238.66348)
		(width 0.18288)
		(layer "In2.Cu")
		(net "M_B_CPU1_SB_DQS_DP<4>")
	)
	(segment
		(start 67.84848 -237.842806)
		(end 67.418712 -237.665006)
		(width 0.18288)
		(layer "In2.Cu")
		(net "M_B_CPU1_SB_DQS_DP<4>")
	)
	(segment
		(start 59.97956 -238.263176)
		(end 59.734958 -238.018574)
		(width 0.18288)
		(layer "In2.Cu")
		(net "M_B_CPU1_SB_DQS_DP<4>")
	)
	(segment
		(start 69.092318 -238.358172)
		(end 68.585588 -238.148368)
		(width 0.18288)
		(layer "In2.Cu")
		(net "M_B_CPU1_SB_DQS_DP<4>")
	)
	(segment
		(start 68.518278 -237.985554)
		(end 68.01104 -237.775496)
		(width 0.18288)
		(layer "In2.Cu")
		(net "M_B_CPU1_SB_DQS_DP<4>")
	)
	(segment
		(start 66.273934 -237.15345)
		(end 66.04508 -237.382812)
		(width 0.18288)
		(layer "In2.Cu")
		(net "M_B_CPU1_SB_DQS_DP<4>")
	)
	(segment
		(start 68.585588 -238.148368)
		(end 68.518278 -237.985554)
		(width 0.18288)
		(layer "In2.Cu")
		(net "M_B_CPU1_SB_DQS_DP<4>")
	)
	(segment
		(start 58.257186 -237.626906)
		(end 58.228992 -237.6551)
		(width 0.16002)
		(layer "In2.Cu")
		(net "M_B_CPU1_SB_DQS_DP<4>")
	)
	(segment
		(start 52.564792 -236.5502)
		(end 52.564792 -236.565948)
		(width 0.16002)
		(layer "In2.Cu")
		(net "M_B_CPU1_SB_DQS_DP<4>")
	)
	(segment
		(start 65.681606 -237.746286)
		(end 64.412622 -237.746286)
		(width 0.18288)
		(layer "In2.Cu")
		(net "M_B_CPU1_SB_DQS_DP<4>")
	)
	(segment
		(start 54.60111 -236.90961)
		(end 54.488334 -236.796834)
		(width 0.18288)
		(layer "In2.Cu")
		(net "M_B_CPU1_SB_DQS_DP<4>")
	)
	(segment
		(start 65.817242 -237.626906)
		(end 65.800986 -237.626906)
		(width 0.16002)
		(layer "In2.Cu")
		(net "M_B_CPU1_SB_DQS_DP<4>")
	)
	(segment
		(start 58.273442 -237.626906)
		(end 58.257186 -237.626906)
		(width 0.16002)
		(layer "In2.Cu")
		(net "M_B_CPU1_SB_DQS_DP<4>")
	)
	(segment
		(start 64.412622 -237.746286)
		(end 64.351916 -237.68558)
		(width 0.18288)
		(layer "In2.Cu")
		(net "M_B_CPU1_SB_DQS_DP<4>")
	)
	(segment
		(start 69.254878 -238.290862)
		(end 69.092318 -238.358172)
		(width 0.18288)
		(layer "In2.Cu")
		(net "M_B_CPU1_SB_DQS_DP<4>")
	)
	(segment
		(start 70.498716 -238.805974)
		(end 70.336156 -238.873284)
		(width 0.18288)
		(layer "In2.Cu")
		(net "M_B_CPU1_SB_DQS_DP<4>")
	)
	(segment
		(start 83.914234 -242.543076)
		(end 83.553046 -242.543076)
		(width 0.088646)
		(layer "In2.Cu")
		(net "M_B_CPU1_SB_DQS_DP<4>")
	)
	(segment
		(start 54.216046 -236.524546)
		(end 53.92801 -236.23651)
		(width 0.18288)
		(layer "In2.Cu")
		(net "M_B_CPU1_SB_DQS_DP<4>")
	)
	(segment
		(start 58.155078 -237.729014)
		(end 56.85155 -237.729014)
		(width 0.18288)
		(layer "In2.Cu")
		(net "M_B_CPU1_SB_DQS_DP<4>")
	)
	(segment
		(start 83.504532 -242.59159)
		(end 83.12404 -242.59159)
		(width 0.088646)
		(layer "In2.Cu")
		(net "M_B_CPU1_SB_DQS_DP<4>")
	)
	(segment
		(start 85.512656 -242.619276)
		(end 85.504274 -242.624102)
		(width 0.088646)
		(layer "In2.Cu")
		(net "M_B_CPU1_SB_DQS_DP<4>")
	)
	(segment
		(start 59.734958 -238.018574)
		(end 59.734958 -237.716822)
		(width 0.18288)
		(layer "In2.Cu")
		(net "M_B_CPU1_SB_DQS_DP<4>")
	)
	(segment
		(start 74.773028 -242.531646)
		(end 71.665084 -239.423702)
		(width 0.18288)
		(layer "In2.Cu")
		(net "M_B_CPU1_SB_DQS_DP<4>")
	)
	(segment
		(start 61.700918 -238.47679)
		(end 61.672724 -238.504984)
		(width 0.16002)
		(layer "In2.Cu")
		(net "M_B_CPU1_SB_DQS_DP<4>")
	)
	(segment
		(start 56.533542 -237.427262)
		(end 56.533542 -237.411006)
		(width 0.16002)
		(layer "In2.Cu")
		(net "M_B_CPU1_SB_DQS_DP<4>")
	)
	(segment
		(start 85.138514 -242.619276)
		(end 85.123782 -242.61064)
		(width 0.088646)
		(layer "In2.Cu")
		(net "M_B_CPU1_SB_DQS_DP<4>")
	)
	(segment
		(start 68.01104 -237.775496)
		(end 67.84848 -237.842806)
		(width 0.18288)
		(layer "In2.Cu")
		(net "M_B_CPU1_SB_DQS_DP<4>")
	)
	(segment
		(start 83.12404 -242.59159)
		(end 83.064096 -242.531646)
		(width 0.088646)
		(layer "In2.Cu")
		(net "M_B_CPU1_SB_DQS_DP<4>")
	)
	(segment
		(start 51.658012 -236.671104)
		(end 51.318922 -236.671104)
		(width 0.18288)
		(layer "In2.Cu")
		(net "M_B_CPU1_SB_DQS_DP<4>")
	)
	(segment
		(start 60.223654 -238.50727)
		(end 60.207398 -238.50727)
		(width 0.16002)
		(layer "In2.Cu")
		(net "M_B_CPU1_SB_DQS_DP<4>")
	)
	(segment
		(start 69.829426 -238.66348)
		(end 69.762116 -238.500666)
		(width 0.18288)
		(layer "In2.Cu")
		(net "M_B_CPU1_SB_DQS_DP<4>")
	)
	(segment
		(start 64.107822 -237.441486)
		(end 64.079628 -237.413292)
		(width 0.16002)
		(layer "In2.Cu")
		(net "M_B_CPU1_SB_DQS_DP<4>")
	)
	(segment
		(start 61.717174 -238.47679)
		(end 61.700918 -238.47679)
		(width 0.16002)
		(layer "In2.Cu")
		(net "M_B_CPU1_SB_DQS_DP<4>")
	)
	(segment
		(start 56.733186 -237.626906)
		(end 56.533542 -237.427262)
		(width 0.16002)
		(layer "In2.Cu")
		(net "M_B_CPU1_SB_DQS_DP<4>")
	)
	(segment
		(start 51.318922 -236.671104)
		(end 51.064414 -236.416596)
		(width 0.18288)
		(layer "In2.Cu")
		(net "M_B_CPU1_SB_DQS_DP<4>")
	)
	(segment
		(start 58.683906 -237.200186)
		(end 58.50128 -237.382812)
		(width 0.18288)
		(layer "In2.Cu")
		(net "M_B_CPU1_SB_DQS_DP<4>")
	)
	(segment
		(start 64.307466 -237.657386)
		(end 64.107822 -237.457742)
		(width 0.16002)
		(layer "In2.Cu")
		(net "M_B_CPU1_SB_DQS_DP<4>")
	)
	(segment
		(start 51.853338 -236.86643)
		(end 51.658012 -236.671104)
		(width 0.18288)
		(layer "In2.Cu")
		(net "M_B_CPU1_SB_DQS_DP<4>")
	)
	(segment
		(start 56.777636 -237.6551)
		(end 56.749442 -237.626906)
		(width 0.16002)
		(layer "In2.Cu")
		(net "M_B_CPU1_SB_DQS_DP<4>")
	)
	(segment
		(start 89.287096 -242.61064)
		(end 89.272364 -242.619276)
		(width 0.088646)
		(layer "In2.Cu")
		(net "M_B_CPU1_SB_DQS_DP<4>")
	)
	(segment
		(start 54.24424 -236.568488)
		(end 54.24424 -236.55274)
		(width 0.16002)
		(layer "In2.Cu")
		(net "M_B_CPU1_SB_DQS_DP<4>")
	)
	(segment
		(start 69.762116 -238.500666)
		(end 69.254878 -238.290862)
		(width 0.18288)
		(layer "In2.Cu")
		(net "M_B_CPU1_SB_DQS_DP<4>")
	)
	(segment
		(start 65.800986 -237.626906)
		(end 65.772792 -237.6551)
		(width 0.16002)
		(layer "In2.Cu")
		(net "M_B_CPU1_SB_DQS_DP<4>")
	)
	(segment
		(start 61.945012 -238.232696)
		(end 61.916818 -238.26089)
		(width 0.16002)
		(layer "In2.Cu")
		(net "M_B_CPU1_SB_DQS_DP<4>")
	)
	(segment
		(start 65.772792 -237.6551)
		(end 65.681606 -237.746286)
		(width 0.18288)
		(layer "In2.Cu")
		(net "M_B_CPU1_SB_DQS_DP<4>")
	)
	(segment
		(start 90.221054 -242.614196)
		(end 90.212164 -242.619276)
		(width 0.088646)
		(layer "In2.Cu")
		(net "M_B_CPU1_SB_DQS_DP<4>")
	)
	(arc
		(start 90.212164 -242.619276)
		(mid 90.024966 -242.669419)
		(end 89.837768 -242.619276)
		(width 0.088646)
		(layer "In2.Cu")
		(net "M_B_CPU1_SB_DQS_DP<4>")
	)
	(arc
		(start 90.395044 -242.352068)
		(mid 90.336925 -242.502309)
		(end 90.221054 -242.614196)
		(width 0.088646)
		(layer "In2.Cu")
		(net "M_B_CPU1_SB_DQS_DP<4>")
	)
	(arc
		(start 85.504274 -242.624102)
		(mid 85.320766 -242.66938)
		(end 85.138514 -242.619276)
		(width 0.088646)
		(layer "In2.Cu")
		(net "M_B_CPU1_SB_DQS_DP<4>")
	)
	(arc
		(start 86.07806 -242.619276)
		(mid 85.807327 -242.543296)
		(end 85.533484 -242.607084)
		(width 0.088646)
		(layer "In2.Cu")
		(net "M_B_CPU1_SB_DQS_DP<4>")
	)
	(arc
		(start 86.438232 -242.627658)
		(mid 86.257069 -242.669598)
		(end 86.07806 -242.619276)
		(width 0.088646)
		(layer "In2.Cu")
		(net "M_B_CPU1_SB_DQS_DP<4>")
	)
	(arc
		(start 84.554822 -242.62969)
		(mid 84.375085 -242.669854)
		(end 84.197952 -242.61953)
		(width 0.088646)
		(layer "In2.Cu")
		(net "M_B_CPU1_SB_DQS_DP<4>")
	)
	(arc
		(start 88.897968 -242.619276)
		(mid 88.623739 -242.543351)
		(end 88.347296 -242.61064)
		(width 0.088646)
		(layer "In2.Cu")
		(net "M_B_CPU1_SB_DQS_DP<4>")
	)
	(arc
		(start 89.272364 -242.619276)
		(mid 89.085166 -242.669419)
		(end 88.897968 -242.619276)
		(width 0.088646)
		(layer "In2.Cu")
		(net "M_B_CPU1_SB_DQS_DP<4>")
	)
	(arc
		(start 88.324182 -242.624102)
		(mid 88.140674 -242.66938)
		(end 87.958422 -242.619276)
		(width 0.088646)
		(layer "In2.Cu")
		(net "M_B_CPU1_SB_DQS_DP<4>")
	)
	(arc
		(start 87.39251 -242.619276)
		(mid 87.205312 -242.669419)
		(end 87.018114 -242.619276)
		(width 0.088646)
		(layer "In2.Cu")
		(net "M_B_CPU1_SB_DQS_DP<4>")
	)
	(arc
		(start 84.197952 -242.61953)
		(mid 84.076799 -242.56691)
		(end 83.946746 -242.543838)
		(width 0.088646)
		(layer "In2.Cu")
		(net "M_B_CPU1_SB_DQS_DP<4>")
	)
	(arc
		(start 87.018114 -242.619276)
		(mid 86.743885 -242.543351)
		(end 86.467442 -242.61064)
		(width 0.088646)
		(layer "In2.Cu")
		(net "M_B_CPU1_SB_DQS_DP<4>")
	)
	(arc
		(start 83.946746 -242.543838)
		(mid 83.930495 -242.543225)
		(end 83.914234 -242.543076)
		(width 0.088646)
		(layer "In2.Cu")
		(net "M_B_CPU1_SB_DQS_DP<4>")
	)
	(arc
		(start 89.837768 -242.619276)
		(mid 89.563539 -242.543351)
		(end 89.287096 -242.61064)
		(width 0.088646)
		(layer "In2.Cu")
		(net "M_B_CPU1_SB_DQS_DP<4>")
	)
	(arc
		(start 85.123782 -242.61064)
		(mid 84.847341 -242.543474)
		(end 84.57311 -242.619276)
		(width 0.088646)
		(layer "In2.Cu")
		(net "M_B_CPU1_SB_DQS_DP<4>")
	)
	(arc
		(start 87.958422 -242.619276)
		(mid 87.675466 -242.543407)
		(end 87.39251 -242.619276)
		(width 0.088646)
		(layer "In2.Cu")
		(net "M_B_CPU1_SB_DQS_DP<4>")
	)
	(segment
		(start 40.175688 -200.880726)
		(end 39.539672 -200.45553)
		(width 0.20066)
		(layer "F.Cu")
		(net "M_B_CPU1_SB_DQS_DP<3>")
	)
	(segment
		(start 44.355766 -200.880726)
		(end 44.029884 -200.880726)
		(width 0.20066)
		(layer "F.Cu")
		(net "M_B_CPU1_SB_DQS_DP<3>")
	)
	(segment
		(start 44.780962 -200.45553)
		(end 44.355766 -200.880726)
		(width 0.20066)
		(layer "F.Cu")
		(net "M_B_CPU1_SB_DQS_DP<3>")
	)
	(segment
		(start 38.853618 -200.716642)
		(end 38.315646 -200.716642)
		(width 0.20066)
		(layer "F.Cu")
		(net "M_B_CPU1_SB_DQS_DP<3>")
	)
	(segment
		(start 45.310806 -200.716642)
		(end 45.049694 -200.45553)
		(width 0.20066)
		(layer "F.Cu")
		(net "M_B_CPU1_SB_DQS_DP<3>")
	)
	(segment
		(start 40.802814 -200.880726)
		(end 40.175688 -200.880726)
		(width 0.20066)
		(layer "F.Cu")
		(net "M_B_CPU1_SB_DQS_DP<3>")
	)
	(segment
		(start 41.073324 -201.151236)
		(end 40.802814 -200.880726)
		(width 0.20066)
		(layer "F.Cu")
		(net "M_B_CPU1_SB_DQS_DP<3>")
	)
	(segment
		(start 41.300908 -201.141838)
		(end 41.29151 -201.151236)
		(width 0.101854)
		(layer "F.Cu")
		(net "M_B_CPU1_SB_DQS_DP<3>")
	)
	(segment
		(start 46.964346 -200.716642)
		(end 45.859446 -200.716642)
		(width 0.20066)
		(layer "F.Cu")
		(net "M_B_CPU1_SB_DQS_DP<3>")
	)
	(segment
		(start 43.293284 -201.141838)
		(end 41.53789 -201.141838)
		(width 0.1016)
		(layer "F.Cu")
		(net "M_B_CPU1_SB_DQS_DP<3>")
	)
	(segment
		(start 85.795866 -225.739198)
		(end 85.795866 -225.203258)
		(width 0.20066)
		(layer "F.Cu")
		(net "M_B_CPU1_SB_DQS_DP<3>")
	)
	(segment
		(start 39.539672 -200.45553)
		(end 39.11473 -200.45553)
		(width 0.20066)
		(layer "F.Cu")
		(net "M_B_CPU1_SB_DQS_DP<3>")
	)
	(segment
		(start 39.11473 -200.45553)
		(end 38.853618 -200.716642)
		(width 0.20066)
		(layer "F.Cu")
		(net "M_B_CPU1_SB_DQS_DP<3>")
	)
	(segment
		(start 44.029884 -200.880726)
		(end 43.768772 -201.141838)
		(width 0.20066)
		(layer "F.Cu")
		(net "M_B_CPU1_SB_DQS_DP<3>")
	)
	(segment
		(start 43.616626 -201.141838)
		(end 43.293284 -201.141838)
		(width 0.101854)
		(layer "F.Cu")
		(net "M_B_CPU1_SB_DQS_DP<3>")
	)
	(segment
		(start 45.859446 -200.716642)
		(end 45.310806 -200.716642)
		(width 0.20066)
		(layer "F.Cu")
		(net "M_B_CPU1_SB_DQS_DP<3>")
	)
	(segment
		(start 41.53789 -201.141838)
		(end 41.300908 -201.141838)
		(width 0.101854)
		(layer "F.Cu")
		(net "M_B_CPU1_SB_DQS_DP<3>")
	)
	(segment
		(start 41.29151 -201.151236)
		(end 41.073324 -201.151236)
		(width 0.20066)
		(layer "F.Cu")
		(net "M_B_CPU1_SB_DQS_DP<3>")
	)
	(segment
		(start 45.049694 -200.45553)
		(end 44.780962 -200.45553)
		(width 0.20066)
		(layer "F.Cu")
		(net "M_B_CPU1_SB_DQS_DP<3>")
	)
	(segment
		(start 43.768772 -201.141838)
		(end 43.616626 -201.141838)
		(width 0.20066)
		(layer "F.Cu")
		(net "M_B_CPU1_SB_DQS_DP<3>")
	)
	(segment
		(start 49.480978 -200.243948)
		(end 48.20031 -200.243948)
		(width 0.18288)
		(layer "In4.Cu")
		(net "M_B_CPU1_SB_DQS_DP<3>")
	)
	(segment
		(start 51.256184 -201.141838)
		(end 50.866548 -201.141838)
		(width 0.18288)
		(layer "In4.Cu")
		(net "M_B_CPU1_SB_DQS_DP<3>")
	)
	(segment
		(start 80.447134 -223.38665)
		(end 75.789028 -218.728544)
		(width 0.18288)
		(layer "In4.Cu")
		(net "M_B_CPU1_SB_DQS_DP<3>")
	)
	(segment
		(start 84.33435 -225.041714)
		(end 83.390486 -224.09785)
		(width 0.088646)
		(layer "In4.Cu")
		(net "M_B_CPU1_SB_DQS_DP<3>")
	)
	(segment
		(start 82.731864 -223.38665)
		(end 82.708496 -223.38665)
		(width 0.088646)
		(layer "In4.Cu")
		(net "M_B_CPU1_SB_DQS_DP<3>")
	)
	(segment
		(start 82.791808 -223.326706)
		(end 82.731864 -223.38665)
		(width 0.088646)
		(layer "In4.Cu")
		(net "M_B_CPU1_SB_DQS_DP<3>")
	)
	(segment
		(start 64.03721 -200.076054)
		(end 56.105552 -200.076054)
		(width 0.18288)
		(layer "In4.Cu")
		(net "M_B_CPU1_SB_DQS_DP<3>")
	)
	(segment
		(start 84.481416 -225.203258)
		(end 84.481416 -225.12655)
		(width 0.088646)
		(layer "In4.Cu")
		(net "M_B_CPU1_SB_DQS_DP<3>")
	)
	(segment
		(start 85.795866 -225.203258)
		(end 85.073236 -225.510344)
		(width 0.088646)
		(layer "In4.Cu")
		(net "M_B_CPU1_SB_DQS_DP<3>")
	)
	(segment
		(start 50.866548 -201.141838)
		(end 50.591212 -200.866502)
		(width 0.18288)
		(layer "In4.Cu")
		(net "M_B_CPU1_SB_DQS_DP<3>")
	)
	(segment
		(start 83.390486 -224.09785)
		(end 83.390486 -223.549718)
		(width 0.088646)
		(layer "In4.Cu")
		(net "M_B_CPU1_SB_DQS_DP<3>")
	)
	(segment
		(start 83.390486 -223.549718)
		(end 83.167474 -223.326706)
		(width 0.088646)
		(layer "In4.Cu")
		(net "M_B_CPU1_SB_DQS_DP<3>")
	)
	(segment
		(start 47.738284 -200.43521)
		(end 47.245778 -200.43521)
		(width 0.18288)
		(layer "In4.Cu")
		(net "M_B_CPU1_SB_DQS_DP<3>")
	)
	(segment
		(start 47.245778 -200.43521)
		(end 46.964346 -200.716642)
		(width 0.18288)
		(layer "In4.Cu")
		(net "M_B_CPU1_SB_DQS_DP<3>")
	)
	(segment
		(start 70.225666 -205.298548)
		(end 66.499232 -201.572114)
		(width 0.18288)
		(layer "In4.Cu")
		(net "M_B_CPU1_SB_DQS_DP<3>")
	)
	(segment
		(start 85.073236 -225.510344)
		(end 85.045296 -225.5266)
		(width 0.088646)
		(layer "In4.Cu")
		(net "M_B_CPU1_SB_DQS_DP<3>")
	)
	(segment
		(start 48.20031 -200.243948)
		(end 47.738284 -200.43521)
		(width 0.18288)
		(layer "In4.Cu")
		(net "M_B_CPU1_SB_DQS_DP<3>")
	)
	(segment
		(start 66.499232 -201.572114)
		(end 65.53327 -201.572114)
		(width 0.18288)
		(layer "In4.Cu")
		(net "M_B_CPU1_SB_DQS_DP<3>")
	)
	(segment
		(start 54.724046 -200.874376)
		(end 51.523646 -200.874376)
		(width 0.18288)
		(layer "In4.Cu")
		(net "M_B_CPU1_SB_DQS_DP<3>")
	)
	(segment
		(start 55.45201 -200.729596)
		(end 54.724046 -200.874376)
		(width 0.18288)
		(layer "In4.Cu")
		(net "M_B_CPU1_SB_DQS_DP<3>")
	)
	(segment
		(start 83.167474 -223.326706)
		(end 82.791808 -223.326706)
		(width 0.088646)
		(layer "In4.Cu")
		(net "M_B_CPU1_SB_DQS_DP<3>")
	)
	(segment
		(start 84.481416 -225.12655)
		(end 84.33435 -225.041714)
		(width 0.088646)
		(layer "In4.Cu")
		(net "M_B_CPU1_SB_DQS_DP<3>")
	)
	(segment
		(start 75.789028 -218.728544)
		(end 70.225666 -205.298548)
		(width 0.18288)
		(layer "In4.Cu")
		(net "M_B_CPU1_SB_DQS_DP<3>")
	)
	(segment
		(start 85.045296 -225.5266)
		(end 85.043264 -225.527616)
		(width 0.088646)
		(layer "In4.Cu")
		(net "M_B_CPU1_SB_DQS_DP<3>")
	)
	(segment
		(start 65.53327 -201.572114)
		(end 64.03721 -200.076054)
		(width 0.18288)
		(layer "In4.Cu")
		(net "M_B_CPU1_SB_DQS_DP<3>")
	)
	(segment
		(start 50.103532 -200.866502)
		(end 49.480978 -200.243948)
		(width 0.18288)
		(layer "In4.Cu")
		(net "M_B_CPU1_SB_DQS_DP<3>")
	)
	(segment
		(start 56.105552 -200.076054)
		(end 55.45201 -200.729596)
		(width 0.18288)
		(layer "In4.Cu")
		(net "M_B_CPU1_SB_DQS_DP<3>")
	)
	(segment
		(start 50.591212 -200.866502)
		(end 50.103532 -200.866502)
		(width 0.18288)
		(layer "In4.Cu")
		(net "M_B_CPU1_SB_DQS_DP<3>")
	)
	(segment
		(start 51.523646 -200.874376)
		(end 51.256184 -201.141838)
		(width 0.18288)
		(layer "In4.Cu")
		(net "M_B_CPU1_SB_DQS_DP<3>")
	)
	(segment
		(start 82.708496 -223.38665)
		(end 80.447134 -223.38665)
		(width 0.18288)
		(layer "In4.Cu")
		(net "M_B_CPU1_SB_DQS_DP<3>")
	)
	(arc
		(start 85.043264 -225.527616)
		(mid 84.668789 -225.52757)
		(end 84.481416 -225.203258)
		(width 0.088646)
		(layer "In4.Cu")
		(net "M_B_CPU1_SB_DQS_DP<3>")
	)
	(segment
		(start 43.616626 -210.491832)
		(end 43.293284 -210.491832)
		(width 0.101854)
		(layer "F.Cu")
		(net "M_B_CPU1_SB_DQS_DP<2>")
	)
	(segment
		(start 44.780962 -209.805524)
		(end 44.355766 -210.23072)
		(width 0.20066)
		(layer "F.Cu")
		(net "M_B_CPU1_SB_DQS_DP<2>")
	)
	(segment
		(start 41.29151 -210.50123)
		(end 41.073324 -210.50123)
		(width 0.20066)
		(layer "F.Cu")
		(net "M_B_CPU1_SB_DQS_DP<2>")
	)
	(segment
		(start 43.293284 -210.491832)
		(end 41.53789 -210.491832)
		(width 0.1016)
		(layer "F.Cu")
		(net "M_B_CPU1_SB_DQS_DP<2>")
	)
	(segment
		(start 46.964346 -210.066636)
		(end 45.859446 -210.066636)
		(width 0.20066)
		(layer "F.Cu")
		(net "M_B_CPU1_SB_DQS_DP<2>")
	)
	(segment
		(start 44.355766 -210.23072)
		(end 44.029884 -210.23072)
		(width 0.20066)
		(layer "F.Cu")
		(net "M_B_CPU1_SB_DQS_DP<2>")
	)
	(segment
		(start 39.539672 -209.805524)
		(end 39.11473 -209.805524)
		(width 0.20066)
		(layer "F.Cu")
		(net "M_B_CPU1_SB_DQS_DP<2>")
	)
	(segment
		(start 45.859446 -210.066636)
		(end 45.310806 -210.066636)
		(width 0.20066)
		(layer "F.Cu")
		(net "M_B_CPU1_SB_DQS_DP<2>")
	)
	(segment
		(start 40.802814 -210.23072)
		(end 40.175688 -210.23072)
		(width 0.20066)
		(layer "F.Cu")
		(net "M_B_CPU1_SB_DQS_DP<2>")
	)
	(segment
		(start 43.768772 -210.491832)
		(end 43.616626 -210.491832)
		(width 0.20066)
		(layer "F.Cu")
		(net "M_B_CPU1_SB_DQS_DP<2>")
	)
	(segment
		(start 41.073324 -210.50123)
		(end 40.802814 -210.23072)
		(width 0.20066)
		(layer "F.Cu")
		(net "M_B_CPU1_SB_DQS_DP<2>")
	)
	(segment
		(start 45.310806 -210.066636)
		(end 45.049694 -209.805524)
		(width 0.20066)
		(layer "F.Cu")
		(net "M_B_CPU1_SB_DQS_DP<2>")
	)
	(segment
		(start 41.53789 -210.491832)
		(end 41.300908 -210.491832)
		(width 0.101854)
		(layer "F.Cu")
		(net "M_B_CPU1_SB_DQS_DP<2>")
	)
	(segment
		(start 89.084912 -228.1809)
		(end 89.085166 -228.180646)
		(width 0.20066)
		(layer "F.Cu")
		(net "M_B_CPU1_SB_DQS_DP<2>")
	)
	(segment
		(start 89.085166 -228.180646)
		(end 89.085166 -227.64496)
		(width 0.20066)
		(layer "F.Cu")
		(net "M_B_CPU1_SB_DQS_DP<2>")
	)
	(segment
		(start 44.029884 -210.23072)
		(end 43.768772 -210.491832)
		(width 0.20066)
		(layer "F.Cu")
		(net "M_B_CPU1_SB_DQS_DP<2>")
	)
	(segment
		(start 40.175688 -210.23072)
		(end 39.539672 -209.805524)
		(width 0.20066)
		(layer "F.Cu")
		(net "M_B_CPU1_SB_DQS_DP<2>")
	)
	(segment
		(start 41.300908 -210.491832)
		(end 41.29151 -210.50123)
		(width 0.101854)
		(layer "F.Cu")
		(net "M_B_CPU1_SB_DQS_DP<2>")
	)
	(segment
		(start 45.049694 -209.805524)
		(end 44.780962 -209.805524)
		(width 0.20066)
		(layer "F.Cu")
		(net "M_B_CPU1_SB_DQS_DP<2>")
	)
	(segment
		(start 39.11473 -209.805524)
		(end 38.853618 -210.066636)
		(width 0.20066)
		(layer "F.Cu")
		(net "M_B_CPU1_SB_DQS_DP<2>")
	)
	(segment
		(start 38.853618 -210.066636)
		(end 38.315646 -210.066636)
		(width 0.20066)
		(layer "F.Cu")
		(net "M_B_CPU1_SB_DQS_DP<2>")
	)
	(segment
		(start 58.937144 -209.33537)
		(end 58.720482 -209.552032)
		(width 0.18288)
		(layer "In2.Cu")
		(net "M_B_CPU1_SB_DQS_DP<2>")
	)
	(segment
		(start 59.94908 -209.100674)
		(end 59.714384 -209.33537)
		(width 0.18288)
		(layer "In2.Cu")
		(net "M_B_CPU1_SB_DQS_DP<2>")
	)
	(segment
		(start 86.640162 -226.027234)
		(end 86.640162 -226.008692)
		(width 0.088646)
		(layer "In2.Cu")
		(net "M_B_CPU1_SB_DQS_DP<2>")
	)
	(segment
		(start 61.916818 -209.07248)
		(end 61.916818 -209.056224)
		(width 0.16002)
		(layer "In2.Cu")
		(net "M_B_CPU1_SB_DQS_DP<2>")
	)
	(segment
		(start 66.236088 -209.580226)
		(end 66.22034 -209.580226)
		(width 0.16002)
		(layer "In2.Cu")
		(net "M_B_CPU1_SB_DQS_DP<2>")
	)
	(segment
		(start 58.692288 -209.580226)
		(end 58.67654 -209.580226)
		(width 0.16002)
		(layer "In2.Cu")
		(net "M_B_CPU1_SB_DQS_DP<2>")
	)
	(segment
		(start 63.829946 -209.552032)
		(end 63.640462 -209.362548)
		(width 0.18288)
		(layer "In2.Cu")
		(net "M_B_CPU1_SB_DQS_DP<2>")
	)
	(segment
		(start 61.717174 -208.85658)
		(end 61.700918 -208.85658)
		(width 0.16002)
		(layer "In2.Cu")
		(net "M_B_CPU1_SB_DQS_DP<2>")
	)
	(segment
		(start 47.645828 -209.796634)
		(end 47.234348 -209.796634)
		(width 0.18288)
		(layer "In2.Cu")
		(net "M_B_CPU1_SB_DQS_DP<2>")
	)
	(segment
		(start 59.977274 -209.056224)
		(end 59.977274 -209.07248)
		(width 0.16002)
		(layer "In2.Cu")
		(net "M_B_CPU1_SB_DQS_DP<2>")
	)
	(segment
		(start 85.043264 -223.251268)
		(end 85.042502 -223.251014)
		(width 0.088646)
		(layer "In2.Cu")
		(net "M_B_CPU1_SB_DQS_DP<2>")
	)
	(segment
		(start 64.07404 -209.796126)
		(end 64.07404 -209.780378)
		(width 0.16002)
		(layer "In2.Cu")
		(net "M_B_CPU1_SB_DQS_DP<2>")
	)
	(segment
		(start 55.65648 -209.36585)
		(end 54.620414 -210.401916)
		(width 0.18288)
		(layer "In2.Cu")
		(net "M_B_CPU1_SB_DQS_DP<2>")
	)
	(segment
		(start 66.020188 -209.796126)
		(end 65.991994 -209.82432)
		(width 0.16002)
		(layer "In2.Cu")
		(net "M_B_CPU1_SB_DQS_DP<2>")
	)
	(segment
		(start 56.741568 -210.007454)
		(end 56.558434 -209.82432)
		(width 0.18288)
		(layer "In2.Cu")
		(net "M_B_CPU1_SB_DQS_DP<2>")
	)
	(segment
		(start 56.31434 -209.580226)
		(end 56.286146 -209.552032)
		(width 0.16002)
		(layer "In2.Cu")
		(net "M_B_CPU1_SB_DQS_DP<2>")
	)
	(segment
		(start 60.313824 -208.73593)
		(end 60.221368 -208.828386)
		(width 0.18288)
		(layer "In2.Cu")
		(net "M_B_CPU1_SB_DQS_DP<2>")
	)
	(segment
		(start 51.52009 -210.218782)
		(end 51.247294 -210.491578)
		(width 0.18288)
		(layer "In2.Cu")
		(net "M_B_CPU1_SB_DQS_DP<2>")
	)
	(segment
		(start 48.263048 -209.54111)
		(end 47.645828 -209.796634)
		(width 0.18288)
		(layer "In2.Cu")
		(net "M_B_CPU1_SB_DQS_DP<2>")
	)
	(segment
		(start 54.59222 -210.43011)
		(end 54.576472 -210.43011)
		(width 0.16002)
		(layer "In2.Cu")
		(net "M_B_CPU1_SB_DQS_DP<2>")
	)
	(segment
		(start 61.916818 -209.056224)
		(end 61.717174 -208.85658)
		(width 0.16002)
		(layer "In2.Cu")
		(net "M_B_CPU1_SB_DQS_DP<2>")
	)
	(segment
		(start 63.85814 -209.580226)
		(end 63.829946 -209.552032)
		(width 0.16002)
		(layer "In2.Cu")
		(net "M_B_CPU1_SB_DQS_DP<2>")
	)
	(segment
		(start 58.67654 -209.580226)
		(end 58.476388 -209.780378)
		(width 0.16002)
		(layer "In2.Cu")
		(net "M_B_CPU1_SB_DQS_DP<2>")
	)
	(segment
		(start 64.07404 -209.780378)
		(end 63.873888 -209.580226)
		(width 0.16002)
		(layer "In2.Cu")
		(net "M_B_CPU1_SB_DQS_DP<2>")
	)
	(segment
		(start 61.945012 -209.100674)
		(end 61.916818 -209.07248)
		(width 0.16002)
		(layer "In2.Cu")
		(net "M_B_CPU1_SB_DQS_DP<2>")
	)
	(segment
		(start 49.139094 -209.96402)
		(end 49.1109 -209.935826)
		(width 0.16002)
		(layer "In2.Cu")
		(net "M_B_CPU1_SB_DQS_DP<2>")
	)
	(segment
		(start 58.26506 -210.007454)
		(end 56.741568 -210.007454)
		(width 0.18288)
		(layer "In2.Cu")
		(net "M_B_CPU1_SB_DQS_DP<2>")
	)
	(segment
		(start 88.334596 -227.968302)
		(end 88.332564 -227.969318)
		(width 0.088646)
		(layer "In2.Cu")
		(net "M_B_CPU1_SB_DQS_DP<2>")
	)
	(segment
		(start 66.020188 -209.780378)
		(end 66.020188 -209.796126)
		(width 0.16002)
		(layer "In2.Cu")
		(net "M_B_CPU1_SB_DQS_DP<2>")
	)
	(segment
		(start 69.942456 -209.605118)
		(end 66.806064 -209.605118)
		(width 0.18288)
		(layer "In2.Cu")
		(net "M_B_CPU1_SB_DQS_DP<2>")
	)
	(segment
		(start 86.927182 -226.509326)
		(end 86.92261 -226.506786)
		(width 0.088646)
		(layer "In2.Cu")
		(net "M_B_CPU1_SB_DQS_DP<2>")
	)
	(segment
		(start 66.3702 -209.446114)
		(end 66.264282 -209.552032)
		(width 0.18288)
		(layer "In2.Cu")
		(net "M_B_CPU1_SB_DQS_DP<2>")
	)
	(segment
		(start 63.873888 -209.580226)
		(end 63.85814 -209.580226)
		(width 0.16002)
		(layer "In2.Cu")
		(net "M_B_CPU1_SB_DQS_DP<2>")
	)
	(segment
		(start 66.264282 -209.552032)
		(end 66.236088 -209.580226)
		(width 0.16002)
		(layer "In2.Cu")
		(net "M_B_CPU1_SB_DQS_DP<2>")
	)
	(segment
		(start 85.230716 -223.59112)
		(end 85.230716 -223.575626)
		(width 0.088646)
		(layer "In2.Cu")
		(net "M_B_CPU1_SB_DQS_DP<2>")
	)
	(segment
		(start 66.22034 -209.580226)
		(end 66.020188 -209.780378)
		(width 0.16002)
		(layer "In2.Cu")
		(net "M_B_CPU1_SB_DQS_DP<2>")
	)
	(segment
		(start 48.895 -209.719926)
		(end 48.866806 -209.691732)
		(width 0.16002)
		(layer "In2.Cu")
		(net "M_B_CPU1_SB_DQS_DP<2>")
	)
	(segment
		(start 86.170516 -225.2218)
		(end 86.170516 -225.203258)
		(width 0.088646)
		(layer "In2.Cu")
		(net "M_B_CPU1_SB_DQS_DP<2>")
	)
	(segment
		(start 50.872898 -210.491578)
		(end 50.615596 -210.234276)
		(width 0.18288)
		(layer "In2.Cu")
		(net "M_B_CPU1_SB_DQS_DP<2>")
	)
	(segment
		(start 58.476388 -209.796126)
		(end 58.448194 -209.82432)
		(width 0.16002)
		(layer "In2.Cu")
		(net "M_B_CPU1_SB_DQS_DP<2>")
	)
	(segment
		(start 60.221368 -208.828386)
		(end 60.193174 -208.85658)
		(width 0.16002)
		(layer "In2.Cu")
		(net "M_B_CPU1_SB_DQS_DP<2>")
	)
	(segment
		(start 86.927182 -226.509072)
		(end 86.927182 -226.509326)
		(width 0.088646)
		(layer "In2.Cu")
		(net "M_B_CPU1_SB_DQS_DP<2>")
	)
	(segment
		(start 86.92769 -226.509326)
		(end 86.927182 -226.509072)
		(width 0.088646)
		(layer "In2.Cu")
		(net "M_B_CPU1_SB_DQS_DP<2>")
	)
	(segment
		(start 60.176918 -208.85658)
		(end 59.977274 -209.056224)
		(width 0.16002)
		(layer "In2.Cu")
		(net "M_B_CPU1_SB_DQS_DP<2>")
	)
	(segment
		(start 86.932008 -226.511866)
		(end 86.92769 -226.509326)
		(width 0.088646)
		(layer "In2.Cu")
		(net "M_B_CPU1_SB_DQS_DP<2>")
	)
	(segment
		(start 54.37632 -210.630262)
		(end 54.37632 -210.64601)
		(width 0.16002)
		(layer "In2.Cu")
		(net "M_B_CPU1_SB_DQS_DP<2>")
	)
	(segment
		(start 84.068158 -223.531938)
		(end 83.869276 -223.531938)
		(width 0.18288)
		(layer "In2.Cu")
		(net "M_B_CPU1_SB_DQS_DP<2>")
	)
	(segment
		(start 54.37632 -210.64601)
		(end 54.348126 -210.674204)
		(width 0.16002)
		(layer "In2.Cu")
		(net "M_B_CPU1_SB_DQS_DP<2>")
	)
	(segment
		(start 52.430172 -210.64601)
		(end 52.430172 -210.630262)
		(width 0.16002)
		(layer "In2.Cu")
		(net "M_B_CPU1_SB_DQS_DP<2>")
	)
	(segment
		(start 87.958168 -227.969318)
		(end 87.949278 -227.964238)
		(width 0.088646)
		(layer "In2.Cu")
		(net "M_B_CPU1_SB_DQS_DP<2>")
	)
	(segment
		(start 58.448194 -209.82432)
		(end 58.26506 -210.007454)
		(width 0.18288)
		(layer "In2.Cu")
		(net "M_B_CPU1_SB_DQS_DP<2>")
	)
	(segment
		(start 52.6415 -210.857338)
		(end 52.458366 -210.674204)
		(width 0.18288)
		(layer "In2.Cu")
		(net "M_B_CPU1_SB_DQS_DP<2>")
	)
	(segment
		(start 58.720482 -209.552032)
		(end 58.692288 -209.580226)
		(width 0.16002)
		(layer "In2.Cu")
		(net "M_B_CPU1_SB_DQS_DP<2>")
	)
	(segment
		(start 65.80886 -210.007454)
		(end 64.285368 -210.007454)
		(width 0.18288)
		(layer "In2.Cu")
		(net "M_B_CPU1_SB_DQS_DP<2>")
	)
	(segment
		(start 49.40935 -210.234276)
		(end 49.139094 -209.96402)
		(width 0.18288)
		(layer "In2.Cu")
		(net "M_B_CPU1_SB_DQS_DP<2>")
	)
	(segment
		(start 56.099964 -209.36585)
		(end 55.65648 -209.36585)
		(width 0.18288)
		(layer "In2.Cu")
		(net "M_B_CPU1_SB_DQS_DP<2>")
	)
	(segment
		(start 54.620414 -210.401916)
		(end 54.59222 -210.43011)
		(width 0.16002)
		(layer "In2.Cu")
		(net "M_B_CPU1_SB_DQS_DP<2>")
	)
	(segment
		(start 52.458366 -210.674204)
		(end 52.430172 -210.64601)
		(width 0.16002)
		(layer "In2.Cu")
		(net "M_B_CPU1_SB_DQS_DP<2>")
	)
	(segment
		(start 84.590636 -223.310196)
		(end 84.428584 -223.471994)
		(width 0.088646)
		(layer "In2.Cu")
		(net "M_B_CPU1_SB_DQS_DP<2>")
	)
	(segment
		(start 54.164992 -210.857338)
		(end 52.6415 -210.857338)
		(width 0.18288)
		(layer "In2.Cu")
		(net "M_B_CPU1_SB_DQS_DP<2>")
	)
	(segment
		(start 52.430172 -210.630262)
		(end 52.23002 -210.43011)
		(width 0.16002)
		(layer "In2.Cu")
		(net "M_B_CPU1_SB_DQS_DP<2>")
	)
	(segment
		(start 83.869276 -223.531938)
		(end 69.942456 -209.605118)
		(width 0.18288)
		(layer "In2.Cu")
		(net "M_B_CPU1_SB_DQS_DP<2>")
	)
	(segment
		(start 84.128102 -223.471994)
		(end 84.068158 -223.531938)
		(width 0.088646)
		(layer "In2.Cu")
		(net "M_B_CPU1_SB_DQS_DP<2>")
	)
	(segment
		(start 64.285368 -210.007454)
		(end 64.102234 -209.82432)
		(width 0.18288)
		(layer "In2.Cu")
		(net "M_B_CPU1_SB_DQS_DP<2>")
	)
	(segment
		(start 56.53024 -209.796126)
		(end 56.53024 -209.780378)
		(width 0.16002)
		(layer "In2.Cu")
		(net "M_B_CPU1_SB_DQS_DP<2>")
	)
	(segment
		(start 49.1109 -209.935826)
		(end 49.1109 -209.920078)
		(width 0.16002)
		(layer "In2.Cu")
		(net "M_B_CPU1_SB_DQS_DP<2>")
	)
	(segment
		(start 56.286146 -209.552032)
		(end 56.099964 -209.36585)
		(width 0.18288)
		(layer "In2.Cu")
		(net "M_B_CPU1_SB_DQS_DP<2>")
	)
	(segment
		(start 54.576472 -210.43011)
		(end 54.37632 -210.630262)
		(width 0.16002)
		(layer "In2.Cu")
		(net "M_B_CPU1_SB_DQS_DP<2>")
	)
	(segment
		(start 58.476388 -209.780378)
		(end 58.476388 -209.796126)
		(width 0.16002)
		(layer "In2.Cu")
		(net "M_B_CPU1_SB_DQS_DP<2>")
	)
	(segment
		(start 52.23002 -210.43011)
		(end 52.214272 -210.43011)
		(width 0.16002)
		(layer "In2.Cu")
		(net "M_B_CPU1_SB_DQS_DP<2>")
	)
	(segment
		(start 48.910748 -209.719926)
		(end 48.895 -209.719926)
		(width 0.16002)
		(layer "In2.Cu")
		(net "M_B_CPU1_SB_DQS_DP<2>")
	)
	(segment
		(start 52.214272 -210.43011)
		(end 52.186078 -210.401916)
		(width 0.16002)
		(layer "In2.Cu")
		(net "M_B_CPU1_SB_DQS_DP<2>")
	)
	(segment
		(start 87.770716 -227.538788)
		(end 87.392764 -227.320348)
		(width 0.088646)
		(layer "In2.Cu")
		(net "M_B_CPU1_SB_DQS_DP<2>")
	)
	(segment
		(start 52.002944 -210.218782)
		(end 51.52009 -210.218782)
		(width 0.18288)
		(layer "In2.Cu")
		(net "M_B_CPU1_SB_DQS_DP<2>")
	)
	(segment
		(start 48.716184 -209.54111)
		(end 48.263048 -209.54111)
		(width 0.18288)
		(layer "In2.Cu")
		(net "M_B_CPU1_SB_DQS_DP<2>")
	)
	(segment
		(start 54.348126 -210.674204)
		(end 54.164992 -210.857338)
		(width 0.18288)
		(layer "In2.Cu")
		(net "M_B_CPU1_SB_DQS_DP<2>")
	)
	(segment
		(start 65.991994 -209.82432)
		(end 65.80886 -210.007454)
		(width 0.18288)
		(layer "In2.Cu")
		(net "M_B_CPU1_SB_DQS_DP<2>")
	)
	(segment
		(start 85.513926 -224.065592)
		(end 85.51291 -224.065084)
		(width 0.088646)
		(layer "In2.Cu")
		(net "M_B_CPU1_SB_DQS_DP<2>")
	)
	(segment
		(start 88.362536 -227.952046)
		(end 88.334596 -227.968302)
		(width 0.088646)
		(layer "In2.Cu")
		(net "M_B_CPU1_SB_DQS_DP<2>")
	)
	(segment
		(start 85.991954 -224.88398)
		(end 85.970872 -224.871788)
		(width 0.088646)
		(layer "In2.Cu")
		(net "M_B_CPU1_SB_DQS_DP<2>")
	)
	(segment
		(start 85.052154 -223.256348)
		(end 85.043264 -223.251268)
		(width 0.088646)
		(layer "In2.Cu")
		(net "M_B_CPU1_SB_DQS_DP<2>")
	)
	(segment
		(start 59.714384 -209.33537)
		(end 58.937144 -209.33537)
		(width 0.18288)
		(layer "In2.Cu")
		(net "M_B_CPU1_SB_DQS_DP<2>")
	)
	(segment
		(start 63.640462 -209.362548)
		(end 62.206886 -209.362548)
		(width 0.18288)
		(layer "In2.Cu")
		(net "M_B_CPU1_SB_DQS_DP<2>")
	)
	(segment
		(start 47.234348 -209.796634)
		(end 46.964346 -210.066636)
		(width 0.18288)
		(layer "In2.Cu")
		(net "M_B_CPU1_SB_DQS_DP<2>")
	)
	(segment
		(start 56.558434 -209.82432)
		(end 56.53024 -209.796126)
		(width 0.16002)
		(layer "In2.Cu")
		(net "M_B_CPU1_SB_DQS_DP<2>")
	)
	(segment
		(start 50.615596 -210.234276)
		(end 49.40935 -210.234276)
		(width 0.18288)
		(layer "In2.Cu")
		(net "M_B_CPU1_SB_DQS_DP<2>")
	)
	(segment
		(start 59.977274 -209.07248)
		(end 59.94908 -209.100674)
		(width 0.16002)
		(layer "In2.Cu")
		(net "M_B_CPU1_SB_DQS_DP<2>")
	)
	(segment
		(start 66.806064 -209.605118)
		(end 66.64706 -209.446114)
		(width 0.18288)
		(layer "In2.Cu")
		(net "M_B_CPU1_SB_DQS_DP<2>")
	)
	(segment
		(start 52.186078 -210.401916)
		(end 52.002944 -210.218782)
		(width 0.18288)
		(layer "In2.Cu")
		(net "M_B_CPU1_SB_DQS_DP<2>")
	)
	(segment
		(start 85.5218 -224.070164)
		(end 85.513926 -224.065592)
		(width 0.088646)
		(layer "In2.Cu")
		(net "M_B_CPU1_SB_DQS_DP<2>")
	)
	(segment
		(start 85.042756 -223.250506)
		(end 85.030818 -223.243648)
		(width 0.088646)
		(layer "In2.Cu")
		(net "M_B_CPU1_SB_DQS_DP<2>")
	)
	(segment
		(start 64.102234 -209.82432)
		(end 64.07404 -209.796126)
		(width 0.16002)
		(layer "In2.Cu")
		(net "M_B_CPU1_SB_DQS_DP<2>")
	)
	(segment
		(start 62.206886 -209.362548)
		(end 61.945012 -209.100674)
		(width 0.18288)
		(layer "In2.Cu")
		(net "M_B_CPU1_SB_DQS_DP<2>")
	)
	(segment
		(start 61.700918 -208.85658)
		(end 61.672724 -208.828386)
		(width 0.16002)
		(layer "In2.Cu")
		(net "M_B_CPU1_SB_DQS_DP<2>")
	)
	(segment
		(start 56.330088 -209.580226)
		(end 56.31434 -209.580226)
		(width 0.16002)
		(layer "In2.Cu")
		(net "M_B_CPU1_SB_DQS_DP<2>")
	)
	(segment
		(start 84.428584 -223.471994)
		(end 84.128102 -223.471994)
		(width 0.088646)
		(layer "In2.Cu")
		(net "M_B_CPU1_SB_DQS_DP<2>")
	)
	(segment
		(start 60.193174 -208.85658)
		(end 60.176918 -208.85658)
		(width 0.16002)
		(layer "In2.Cu")
		(net "M_B_CPU1_SB_DQS_DP<2>")
	)
	(segment
		(start 61.580268 -208.73593)
		(end 60.313824 -208.73593)
		(width 0.18288)
		(layer "In2.Cu")
		(net "M_B_CPU1_SB_DQS_DP<2>")
	)
	(segment
		(start 89.085166 -227.64496)
		(end 88.362536 -227.952046)
		(width 0.088646)
		(layer "In2.Cu")
		(net "M_B_CPU1_SB_DQS_DP<2>")
	)
	(segment
		(start 87.770716 -227.64496)
		(end 87.770716 -227.538788)
		(width 0.088646)
		(layer "In2.Cu")
		(net "M_B_CPU1_SB_DQS_DP<2>")
	)
	(segment
		(start 66.64706 -209.446114)
		(end 66.3702 -209.446114)
		(width 0.18288)
		(layer "In2.Cu")
		(net "M_B_CPU1_SB_DQS_DP<2>")
	)
	(segment
		(start 56.53024 -209.780378)
		(end 56.330088 -209.580226)
		(width 0.16002)
		(layer "In2.Cu")
		(net "M_B_CPU1_SB_DQS_DP<2>")
	)
	(segment
		(start 61.672724 -208.828386)
		(end 61.580268 -208.73593)
		(width 0.18288)
		(layer "In2.Cu")
		(net "M_B_CPU1_SB_DQS_DP<2>")
	)
	(segment
		(start 51.247294 -210.491578)
		(end 50.872898 -210.491578)
		(width 0.18288)
		(layer "In2.Cu")
		(net "M_B_CPU1_SB_DQS_DP<2>")
	)
	(segment
		(start 85.042502 -223.251014)
		(end 85.042756 -223.250506)
		(width 0.088646)
		(layer "In2.Cu")
		(net "M_B_CPU1_SB_DQS_DP<2>")
	)
	(segment
		(start 48.866806 -209.691732)
		(end 48.716184 -209.54111)
		(width 0.18288)
		(layer "In2.Cu")
		(net "M_B_CPU1_SB_DQS_DP<2>")
	)
	(segment
		(start 49.1109 -209.920078)
		(end 48.910748 -209.719926)
		(width 0.16002)
		(layer "In2.Cu")
		(net "M_B_CPU1_SB_DQS_DP<2>")
	)
	(arc
		(start 87.392764 -227.320348)
		(mid 87.186182 -227.113522)
		(end 87.11057 -226.831144)
		(width 0.088646)
		(layer "In2.Cu")
		(net "M_B_CPU1_SB_DQS_DP<2>")
	)
	(arc
		(start 87.11057 -226.831144)
		(mid 87.062891 -226.648244)
		(end 86.932008 -226.511866)
		(width 0.088646)
		(layer "In2.Cu")
		(net "M_B_CPU1_SB_DQS_DP<2>")
	)
	(arc
		(start 85.700362 -224.389442)
		(mid 85.652683 -224.206542)
		(end 85.5218 -224.070164)
		(width 0.088646)
		(layer "In2.Cu")
		(net "M_B_CPU1_SB_DQS_DP<2>")
	)
	(arc
		(start 88.332564 -227.969318)
		(mid 88.145366 -228.019461)
		(end 87.958168 -227.969318)
		(width 0.088646)
		(layer "In2.Cu")
		(net "M_B_CPU1_SB_DQS_DP<2>")
	)
	(arc
		(start 86.640162 -226.008692)
		(mid 86.587892 -225.826327)
		(end 86.452964 -225.69297)
		(width 0.088646)
		(layer "In2.Cu")
		(net "M_B_CPU1_SB_DQS_DP<2>")
	)
	(arc
		(start 86.452964 -225.69297)
		(mid 86.250678 -225.493989)
		(end 86.170516 -225.2218)
		(width 0.088646)
		(layer "In2.Cu")
		(net "M_B_CPU1_SB_DQS_DP<2>")
	)
	(arc
		(start 85.230716 -223.575626)
		(mid 85.183037 -223.392726)
		(end 85.052154 -223.256348)
		(width 0.088646)
		(layer "In2.Cu")
		(net "M_B_CPU1_SB_DQS_DP<2>")
	)
	(arc
		(start 86.170516 -225.203258)
		(mid 86.122837 -225.020358)
		(end 85.991954 -224.88398)
		(width 0.088646)
		(layer "In2.Cu")
		(net "M_B_CPU1_SB_DQS_DP<2>")
	)
	(arc
		(start 85.970872 -224.871788)
		(mid 85.772644 -224.66594)
		(end 85.700362 -224.389442)
		(width 0.088646)
		(layer "In2.Cu")
		(net "M_B_CPU1_SB_DQS_DP<2>")
	)
	(arc
		(start 84.66836 -223.25076)
		(mid 84.65719 -223.257424)
		(end 84.646262 -223.264476)
		(width 0.088646)
		(layer "In2.Cu")
		(net "M_B_CPU1_SB_DQS_DP<2>")
	)
	(arc
		(start 85.030818 -223.243648)
		(mid 84.848677 -223.200535)
		(end 84.66836 -223.25076)
		(width 0.088646)
		(layer "In2.Cu")
		(net "M_B_CPU1_SB_DQS_DP<2>")
	)
	(arc
		(start 87.949278 -227.964238)
		(mid 87.818364 -227.827878)
		(end 87.770716 -227.64496)
		(width 0.088646)
		(layer "In2.Cu")
		(net "M_B_CPU1_SB_DQS_DP<2>")
	)
	(arc
		(start 85.51291 -224.065084)
		(mid 85.310087 -223.864853)
		(end 85.230716 -223.59112)
		(width 0.088646)
		(layer "In2.Cu")
		(net "M_B_CPU1_SB_DQS_DP<2>")
	)
	(arc
		(start 84.646262 -223.264476)
		(mid 84.617347 -223.285996)
		(end 84.590636 -223.310196)
		(width 0.088646)
		(layer "In2.Cu")
		(net "M_B_CPU1_SB_DQS_DP<2>")
	)
	(arc
		(start 86.92261 -226.506786)
		(mid 86.718275 -226.304181)
		(end 86.640162 -226.027234)
		(width 0.088646)
		(layer "In2.Cu")
		(net "M_B_CPU1_SB_DQS_DP<2>")
	)
	(segment
		(start 89.084912 -233.064304)
		(end 89.084912 -232.528618)
		(width 0.20066)
		(layer "F.Cu")
		(net "M_B_CPU1_SB_DQS_DP<1>")
	)
	(segment
		(start 43.768772 -219.841826)
		(end 43.61688 -219.841826)
		(width 0.20066)
		(layer "F.Cu")
		(net "M_B_CPU1_SB_DQS_DP<1>")
	)
	(segment
		(start 89.084912 -232.528618)
		(end 89.085166 -232.528364)
		(width 0.20066)
		(layer "F.Cu")
		(net "M_B_CPU1_SB_DQS_DP<1>")
	)
	(segment
		(start 39.539672 -219.155518)
		(end 39.11473 -219.155518)
		(width 0.20066)
		(layer "F.Cu")
		(net "M_B_CPU1_SB_DQS_DP<1>")
	)
	(segment
		(start 44.029884 -219.580714)
		(end 43.768772 -219.841826)
		(width 0.20066)
		(layer "F.Cu")
		(net "M_B_CPU1_SB_DQS_DP<1>")
	)
	(segment
		(start 43.61688 -219.841826)
		(end 43.293284 -219.841826)
		(width 0.101854)
		(layer "F.Cu")
		(net "M_B_CPU1_SB_DQS_DP<1>")
	)
	(segment
		(start 45.859446 -219.41663)
		(end 45.310806 -219.41663)
		(width 0.20066)
		(layer "F.Cu")
		(net "M_B_CPU1_SB_DQS_DP<1>")
	)
	(segment
		(start 40.175434 -219.580714)
		(end 39.539672 -219.155518)
		(width 0.20066)
		(layer "F.Cu")
		(net "M_B_CPU1_SB_DQS_DP<1>")
	)
	(segment
		(start 46.964346 -219.41663)
		(end 45.859446 -219.41663)
		(width 0.20066)
		(layer "F.Cu")
		(net "M_B_CPU1_SB_DQS_DP<1>")
	)
	(segment
		(start 41.073324 -219.851224)
		(end 40.802814 -219.580714)
		(width 0.20066)
		(layer "F.Cu")
		(net "M_B_CPU1_SB_DQS_DP<1>")
	)
	(segment
		(start 41.291764 -219.85097)
		(end 41.29151 -219.851224)
		(width 0.20066)
		(layer "F.Cu")
		(net "M_B_CPU1_SB_DQS_DP<1>")
	)
	(segment
		(start 44.780962 -219.155518)
		(end 44.355766 -219.580714)
		(width 0.20066)
		(layer "F.Cu")
		(net "M_B_CPU1_SB_DQS_DP<1>")
	)
	(segment
		(start 38.853618 -219.41663)
		(end 38.315646 -219.41663)
		(width 0.20066)
		(layer "F.Cu")
		(net "M_B_CPU1_SB_DQS_DP<1>")
	)
	(segment
		(start 41.29151 -219.851224)
		(end 41.073324 -219.851224)
		(width 0.20066)
		(layer "F.Cu")
		(net "M_B_CPU1_SB_DQS_DP<1>")
	)
	(segment
		(start 45.310806 -219.41663)
		(end 45.049694 -219.155518)
		(width 0.20066)
		(layer "F.Cu")
		(net "M_B_CPU1_SB_DQS_DP<1>")
	)
	(segment
		(start 41.300908 -219.841826)
		(end 41.291764 -219.85097)
		(width 0.101854)
		(layer "F.Cu")
		(net "M_B_CPU1_SB_DQS_DP<1>")
	)
	(segment
		(start 43.293284 -219.841826)
		(end 41.53789 -219.841826)
		(width 0.1016)
		(layer "F.Cu")
		(net "M_B_CPU1_SB_DQS_DP<1>")
	)
	(segment
		(start 45.049694 -219.155518)
		(end 44.780962 -219.155518)
		(width 0.20066)
		(layer "F.Cu")
		(net "M_B_CPU1_SB_DQS_DP<1>")
	)
	(segment
		(start 39.11473 -219.155518)
		(end 38.853618 -219.41663)
		(width 0.20066)
		(layer "F.Cu")
		(net "M_B_CPU1_SB_DQS_DP<1>")
	)
	(segment
		(start 41.53789 -219.841826)
		(end 41.300908 -219.841826)
		(width 0.101854)
		(layer "F.Cu")
		(net "M_B_CPU1_SB_DQS_DP<1>")
	)
	(segment
		(start 40.802814 -219.580714)
		(end 40.175434 -219.580714)
		(width 0.20066)
		(layer "F.Cu")
		(net "M_B_CPU1_SB_DQS_DP<1>")
	)
	(segment
		(start 44.355766 -219.580714)
		(end 44.029884 -219.580714)
		(width 0.20066)
		(layer "F.Cu")
		(net "M_B_CPU1_SB_DQS_DP<1>")
	)
	(segment
		(start 56.31434 -220.630242)
		(end 56.286146 -220.602048)
		(width 0.16002)
		(layer "In2.Cu")
		(net "M_B_CPU1_SB_DQS_DP<1>")
	)
	(segment
		(start 48.895 -219.06992)
		(end 48.866806 -219.041726)
		(width 0.16002)
		(layer "In2.Cu")
		(net "M_B_CPU1_SB_DQS_DP<1>")
	)
	(segment
		(start 48.910748 -219.06992)
		(end 48.895 -219.06992)
		(width 0.16002)
		(layer "In2.Cu")
		(net "M_B_CPU1_SB_DQS_DP<1>")
	)
	(segment
		(start 65.827402 -219.338906)
		(end 64.266826 -219.338906)
		(width 0.18288)
		(layer "In2.Cu")
		(net "M_B_CPU1_SB_DQS_DP<1>")
	)
	(segment
		(start 54.620414 -219.75191)
		(end 54.59222 -219.780104)
		(width 0.16002)
		(layer "In2.Cu")
		(net "M_B_CPU1_SB_DQS_DP<1>")
	)
	(segment
		(start 55.321708 -219.63761)
		(end 54.734714 -219.63761)
		(width 0.18288)
		(layer "In2.Cu")
		(net "M_B_CPU1_SB_DQS_DP<1>")
	)
	(segment
		(start 47.234348 -219.146628)
		(end 46.964346 -219.41663)
		(width 0.18288)
		(layer "In2.Cu")
		(net "M_B_CPU1_SB_DQS_DP<1>")
	)
	(segment
		(start 49.1109 -219.28582)
		(end 49.1109 -219.270072)
		(width 0.16002)
		(layer "In2.Cu")
		(net "M_B_CPU1_SB_DQS_DP<1>")
	)
	(segment
		(start 54.348126 -220.024198)
		(end 54.183534 -220.18879)
		(width 0.18288)
		(layer "In2.Cu")
		(net "M_B_CPU1_SB_DQS_DP<1>")
	)
	(segment
		(start 66.264282 -218.902026)
		(end 66.236088 -218.93022)
		(width 0.16002)
		(layer "In2.Cu")
		(net "M_B_CPU1_SB_DQS_DP<1>")
	)
	(segment
		(start 56.53024 -220.830394)
		(end 56.330088 -220.630242)
		(width 0.16002)
		(layer "In2.Cu")
		(net "M_B_CPU1_SB_DQS_DP<1>")
	)
	(segment
		(start 51.52009 -219.568776)
		(end 51.247294 -219.841572)
		(width 0.18288)
		(layer "In2.Cu")
		(net "M_B_CPU1_SB_DQS_DP<1>")
	)
	(segment
		(start 62.13602 -219.780104)
		(end 62.120272 -219.780104)
		(width 0.16002)
		(layer "In2.Cu")
		(net "M_B_CPU1_SB_DQS_DP<1>")
	)
	(segment
		(start 85.057996 -233.026458)
		(end 85.043264 -233.017822)
		(width 0.088646)
		(layer "In2.Cu")
		(net "M_B_CPU1_SB_DQS_DP<1>")
	)
	(segment
		(start 65.991994 -219.174314)
		(end 65.827402 -219.338906)
		(width 0.18288)
		(layer "In2.Cu")
		(net "M_B_CPU1_SB_DQS_DP<1>")
	)
	(segment
		(start 58.67654 -220.630242)
		(end 58.476388 -220.830394)
		(width 0.16002)
		(layer "In2.Cu")
		(net "M_B_CPU1_SB_DQS_DP<1>")
	)
	(segment
		(start 83.036664 -232.454958)
		(end 69.419724 -218.838018)
		(width 0.18288)
		(layer "In2.Cu")
		(net "M_B_CPU1_SB_DQS_DP<1>")
	)
	(segment
		(start 47.645828 -219.146628)
		(end 47.234348 -219.146628)
		(width 0.18288)
		(layer "In2.Cu")
		(net "M_B_CPU1_SB_DQS_DP<1>")
	)
	(segment
		(start 51.247294 -219.841572)
		(end 50.872898 -219.841572)
		(width 0.18288)
		(layer "In2.Cu")
		(net "M_B_CPU1_SB_DQS_DP<1>")
	)
	(segment
		(start 62.36081 -219.555314)
		(end 62.164214 -219.75191)
		(width 0.18288)
		(layer "In2.Cu")
		(net "M_B_CPU1_SB_DQS_DP<1>")
	)
	(segment
		(start 62.164214 -219.75191)
		(end 62.13602 -219.780104)
		(width 0.16002)
		(layer "In2.Cu")
		(net "M_B_CPU1_SB_DQS_DP<1>")
	)
	(segment
		(start 58.476388 -220.830394)
		(end 58.476388 -220.846142)
		(width 0.16002)
		(layer "In2.Cu")
		(net "M_B_CPU1_SB_DQS_DP<1>")
	)
	(segment
		(start 83.331812 -232.66527)
		(end 83.1215 -232.454958)
		(width 0.088646)
		(layer "In2.Cu")
		(net "M_B_CPU1_SB_DQS_DP<1>")
	)
	(segment
		(start 50.615596 -219.58427)
		(end 49.40935 -219.58427)
		(width 0.18288)
		(layer "In2.Cu")
		(net "M_B_CPU1_SB_DQS_DP<1>")
	)
	(segment
		(start 84.668868 -233.017822)
		(end 84.668614 -233.017314)
		(width 0.088646)
		(layer "In2.Cu")
		(net "M_B_CPU1_SB_DQS_DP<1>")
	)
	(segment
		(start 56.53024 -220.846142)
		(end 56.53024 -220.830394)
		(width 0.16002)
		(layer "In2.Cu")
		(net "M_B_CPU1_SB_DQS_DP<1>")
	)
	(segment
		(start 52.002944 -219.568776)
		(end 51.52009 -219.568776)
		(width 0.18288)
		(layer "In2.Cu")
		(net "M_B_CPU1_SB_DQS_DP<1>")
	)
	(segment
		(start 64.07404 -219.130372)
		(end 63.873888 -218.93022)
		(width 0.16002)
		(layer "In2.Cu")
		(net "M_B_CPU1_SB_DQS_DP<1>")
	)
	(segment
		(start 66.32829 -218.838018)
		(end 66.264282 -218.902026)
		(width 0.18288)
		(layer "In2.Cu")
		(net "M_B_CPU1_SB_DQS_DP<1>")
	)
	(segment
		(start 63.873888 -218.93022)
		(end 63.85814 -218.93022)
		(width 0.16002)
		(layer "In2.Cu")
		(net "M_B_CPU1_SB_DQS_DP<1>")
	)
	(segment
		(start 64.07404 -219.14612)
		(end 64.07404 -219.130372)
		(width 0.16002)
		(layer "In2.Cu")
		(net "M_B_CPU1_SB_DQS_DP<1>")
	)
	(segment
		(start 83.616038 -232.66527)
		(end 83.331812 -232.66527)
		(width 0.088646)
		(layer "In2.Cu")
		(net "M_B_CPU1_SB_DQS_DP<1>")
	)
	(segment
		(start 52.458366 -220.024198)
		(end 52.430172 -219.996004)
		(width 0.16002)
		(layer "In2.Cu")
		(net "M_B_CPU1_SB_DQS_DP<1>")
	)
	(segment
		(start 64.266826 -219.338906)
		(end 64.102234 -219.174314)
		(width 0.18288)
		(layer "In2.Cu")
		(net "M_B_CPU1_SB_DQS_DP<1>")
	)
	(segment
		(start 61.724794 -220.19133)
		(end 60.113418 -220.19133)
		(width 0.18288)
		(layer "In2.Cu")
		(net "M_B_CPU1_SB_DQS_DP<1>")
	)
	(segment
		(start 66.236088 -218.93022)
		(end 66.22034 -218.93022)
		(width 0.16002)
		(layer "In2.Cu")
		(net "M_B_CPU1_SB_DQS_DP<1>")
	)
	(segment
		(start 63.829946 -218.902026)
		(end 63.77432 -218.8464)
		(width 0.18288)
		(layer "In2.Cu")
		(net "M_B_CPU1_SB_DQS_DP<1>")
	)
	(segment
		(start 56.330088 -220.630242)
		(end 56.31434 -220.630242)
		(width 0.16002)
		(layer "In2.Cu")
		(net "M_B_CPU1_SB_DQS_DP<1>")
	)
	(segment
		(start 52.430172 -219.996004)
		(end 52.430172 -219.980256)
		(width 0.16002)
		(layer "In2.Cu")
		(net "M_B_CPU1_SB_DQS_DP<1>")
	)
	(segment
		(start 54.576472 -219.780104)
		(end 54.37632 -219.980256)
		(width 0.16002)
		(layer "In2.Cu")
		(net "M_B_CPU1_SB_DQS_DP<1>")
	)
	(segment
		(start 59.821318 -219.89923)
		(end 59.4233 -219.89923)
		(width 0.18288)
		(layer "In2.Cu")
		(net "M_B_CPU1_SB_DQS_DP<1>")
	)
	(segment
		(start 66.020188 -219.130372)
		(end 66.020188 -219.14612)
		(width 0.16002)
		(layer "In2.Cu")
		(net "M_B_CPU1_SB_DQS_DP<1>")
	)
	(segment
		(start 48.716184 -218.891104)
		(end 48.263048 -218.891104)
		(width 0.18288)
		(layer "In2.Cu")
		(net "M_B_CPU1_SB_DQS_DP<1>")
	)
	(segment
		(start 66.22034 -218.93022)
		(end 66.020188 -219.130372)
		(width 0.16002)
		(layer "In2.Cu")
		(net "M_B_CPU1_SB_DQS_DP<1>")
	)
	(segment
		(start 84.386166 -233.09326)
		(end 84.044028 -233.09326)
		(width 0.088646)
		(layer "In2.Cu")
		(net "M_B_CPU1_SB_DQS_DP<1>")
	)
	(segment
		(start 64.102234 -219.174314)
		(end 64.07404 -219.14612)
		(width 0.16002)
		(layer "In2.Cu")
		(net "M_B_CPU1_SB_DQS_DP<1>")
	)
	(segment
		(start 66.020188 -219.14612)
		(end 65.991994 -219.174314)
		(width 0.16002)
		(layer "In2.Cu")
		(net "M_B_CPU1_SB_DQS_DP<1>")
	)
	(segment
		(start 87.488014 -233.017568)
		(end 87.488268 -233.017822)
		(width 0.088646)
		(layer "In2.Cu")
		(net "M_B_CPU1_SB_DQS_DP<1>")
	)
	(segment
		(start 61.891926 -220.024198)
		(end 61.724794 -220.19133)
		(width 0.18288)
		(layer "In2.Cu")
		(net "M_B_CPU1_SB_DQS_DP<1>")
	)
	(segment
		(start 52.23002 -219.780104)
		(end 52.214272 -219.780104)
		(width 0.16002)
		(layer "In2.Cu")
		(net "M_B_CPU1_SB_DQS_DP<1>")
	)
	(segment
		(start 50.872898 -219.841572)
		(end 50.615596 -219.58427)
		(width 0.18288)
		(layer "In2.Cu")
		(net "M_B_CPU1_SB_DQS_DP<1>")
	)
	(segment
		(start 48.866806 -219.041726)
		(end 48.716184 -218.891104)
		(width 0.18288)
		(layer "In2.Cu")
		(net "M_B_CPU1_SB_DQS_DP<1>")
	)
	(segment
		(start 49.139094 -219.314014)
		(end 49.1109 -219.28582)
		(width 0.16002)
		(layer "In2.Cu")
		(net "M_B_CPU1_SB_DQS_DP<1>")
	)
	(segment
		(start 59.4233 -219.89923)
		(end 58.720482 -220.602048)
		(width 0.18288)
		(layer "In2.Cu")
		(net "M_B_CPU1_SB_DQS_DP<1>")
	)
	(segment
		(start 54.37632 -219.980256)
		(end 54.37632 -219.996004)
		(width 0.16002)
		(layer "In2.Cu")
		(net "M_B_CPU1_SB_DQS_DP<1>")
	)
	(segment
		(start 63.85814 -218.93022)
		(end 63.829946 -218.902026)
		(width 0.16002)
		(layer "In2.Cu")
		(net "M_B_CPU1_SB_DQS_DP<1>")
	)
	(segment
		(start 84.044028 -233.09326)
		(end 83.616038 -232.66527)
		(width 0.088646)
		(layer "In2.Cu")
		(net "M_B_CPU1_SB_DQS_DP<1>")
	)
	(segment
		(start 61.92012 -219.996004)
		(end 61.891926 -220.024198)
		(width 0.16002)
		(layer "In2.Cu")
		(net "M_B_CPU1_SB_DQS_DP<1>")
	)
	(segment
		(start 56.558434 -220.874336)
		(end 56.53024 -220.846142)
		(width 0.16002)
		(layer "In2.Cu")
		(net "M_B_CPU1_SB_DQS_DP<1>")
	)
	(segment
		(start 54.59222 -219.780104)
		(end 54.576472 -219.780104)
		(width 0.16002)
		(layer "In2.Cu")
		(net "M_B_CPU1_SB_DQS_DP<1>")
	)
	(segment
		(start 58.283602 -221.038928)
		(end 56.723026 -221.038928)
		(width 0.18288)
		(layer "In2.Cu")
		(net "M_B_CPU1_SB_DQS_DP<1>")
	)
	(segment
		(start 58.476388 -220.846142)
		(end 58.448194 -220.874336)
		(width 0.16002)
		(layer "In2.Cu")
		(net "M_B_CPU1_SB_DQS_DP<1>")
	)
	(segment
		(start 54.37632 -219.996004)
		(end 54.348126 -220.024198)
		(width 0.16002)
		(layer "In2.Cu")
		(net "M_B_CPU1_SB_DQS_DP<1>")
	)
	(segment
		(start 56.286146 -220.602048)
		(end 55.321708 -219.63761)
		(width 0.18288)
		(layer "In2.Cu")
		(net "M_B_CPU1_SB_DQS_DP<1>")
	)
	(segment
		(start 62.812422 -219.555314)
		(end 62.36081 -219.555314)
		(width 0.18288)
		(layer "In2.Cu")
		(net "M_B_CPU1_SB_DQS_DP<1>")
	)
	(segment
		(start 63.521336 -218.8464)
		(end 62.812422 -219.555314)
		(width 0.18288)
		(layer "In2.Cu")
		(net "M_B_CPU1_SB_DQS_DP<1>")
	)
	(segment
		(start 58.448194 -220.874336)
		(end 58.283602 -221.038928)
		(width 0.18288)
		(layer "In2.Cu")
		(net "M_B_CPU1_SB_DQS_DP<1>")
	)
	(segment
		(start 62.120272 -219.780104)
		(end 61.92012 -219.980256)
		(width 0.16002)
		(layer "In2.Cu")
		(net "M_B_CPU1_SB_DQS_DP<1>")
	)
	(segment
		(start 52.430172 -219.980256)
		(end 52.23002 -219.780104)
		(width 0.16002)
		(layer "In2.Cu")
		(net "M_B_CPU1_SB_DQS_DP<1>")
	)
	(segment
		(start 63.77432 -218.8464)
		(end 63.521336 -218.8464)
		(width 0.18288)
		(layer "In2.Cu")
		(net "M_B_CPU1_SB_DQS_DP<1>")
	)
	(segment
		(start 89.085166 -232.528364)
		(end 88.408256 -232.80878)
		(width 0.088646)
		(layer "In2.Cu")
		(net "M_B_CPU1_SB_DQS_DP<1>")
	)
	(segment
		(start 69.419724 -218.838018)
		(end 66.32829 -218.838018)
		(width 0.18288)
		(layer "In2.Cu")
		(net "M_B_CPU1_SB_DQS_DP<1>")
	)
	(segment
		(start 54.183534 -220.18879)
		(end 52.622958 -220.18879)
		(width 0.18288)
		(layer "In2.Cu")
		(net "M_B_CPU1_SB_DQS_DP<1>")
	)
	(segment
		(start 52.186078 -219.75191)
		(end 52.002944 -219.568776)
		(width 0.18288)
		(layer "In2.Cu")
		(net "M_B_CPU1_SB_DQS_DP<1>")
	)
	(segment
		(start 58.692288 -220.630242)
		(end 58.67654 -220.630242)
		(width 0.16002)
		(layer "In2.Cu")
		(net "M_B_CPU1_SB_DQS_DP<1>")
	)
	(segment
		(start 52.622958 -220.18879)
		(end 52.458366 -220.024198)
		(width 0.18288)
		(layer "In2.Cu")
		(net "M_B_CPU1_SB_DQS_DP<1>")
	)
	(segment
		(start 87.652098 -232.922826)
		(end 87.488014 -233.017568)
		(width 0.088646)
		(layer "In2.Cu")
		(net "M_B_CPU1_SB_DQS_DP<1>")
	)
	(segment
		(start 49.40935 -219.58427)
		(end 49.139094 -219.314014)
		(width 0.18288)
		(layer "In2.Cu")
		(net "M_B_CPU1_SB_DQS_DP<1>")
	)
	(segment
		(start 48.263048 -218.891104)
		(end 47.645828 -219.146628)
		(width 0.18288)
		(layer "In2.Cu")
		(net "M_B_CPU1_SB_DQS_DP<1>")
	)
	(segment
		(start 83.1215 -232.454958)
		(end 83.036664 -232.454958)
		(width 0.088646)
		(layer "In2.Cu")
		(net "M_B_CPU1_SB_DQS_DP<1>")
	)
	(segment
		(start 58.720482 -220.602048)
		(end 58.692288 -220.630242)
		(width 0.16002)
		(layer "In2.Cu")
		(net "M_B_CPU1_SB_DQS_DP<1>")
	)
	(segment
		(start 56.723026 -221.038928)
		(end 56.558434 -220.874336)
		(width 0.18288)
		(layer "In2.Cu")
		(net "M_B_CPU1_SB_DQS_DP<1>")
	)
	(segment
		(start 88.072722 -232.922826)
		(end 87.652098 -232.922826)
		(width 0.088646)
		(layer "In2.Cu")
		(net "M_B_CPU1_SB_DQS_DP<1>")
	)
	(segment
		(start 54.734714 -219.63761)
		(end 54.620414 -219.75191)
		(width 0.18288)
		(layer "In2.Cu")
		(net "M_B_CPU1_SB_DQS_DP<1>")
	)
	(segment
		(start 84.668614 -233.017314)
		(end 84.66836 -233.017568)
		(width 0.088646)
		(layer "In2.Cu")
		(net "M_B_CPU1_SB_DQS_DP<1>")
	)
	(segment
		(start 61.92012 -219.980256)
		(end 61.92012 -219.996004)
		(width 0.16002)
		(layer "In2.Cu")
		(net "M_B_CPU1_SB_DQS_DP<1>")
	)
	(segment
		(start 88.408256 -232.80878)
		(end 88.33231 -232.852722)
		(width 0.088646)
		(layer "In2.Cu")
		(net "M_B_CPU1_SB_DQS_DP<1>")
	)
	(segment
		(start 60.113418 -220.19133)
		(end 59.821318 -219.89923)
		(width 0.18288)
		(layer "In2.Cu")
		(net "M_B_CPU1_SB_DQS_DP<1>")
	)
	(segment
		(start 49.1109 -219.270072)
		(end 48.910748 -219.06992)
		(width 0.16002)
		(layer "In2.Cu")
		(net "M_B_CPU1_SB_DQS_DP<1>")
	)
	(segment
		(start 52.214272 -219.780104)
		(end 52.186078 -219.75191)
		(width 0.16002)
		(layer "In2.Cu")
		(net "M_B_CPU1_SB_DQS_DP<1>")
	)
	(arc
		(start 87.488268 -233.017822)
		(mid 87.205566 -233.093598)
		(end 86.922864 -233.017822)
		(width 0.088646)
		(layer "In2.Cu")
		(net "M_B_CPU1_SB_DQS_DP<1>")
	)
	(arc
		(start 85.608668 -233.017822)
		(mid 85.334469 -233.093657)
		(end 85.057996 -233.026458)
		(width 0.088646)
		(layer "In2.Cu")
		(net "M_B_CPU1_SB_DQS_DP<1>")
	)
	(arc
		(start 86.922864 -233.017822)
		(mid 86.735666 -232.967679)
		(end 86.548468 -233.017822)
		(width 0.088646)
		(layer "In2.Cu")
		(net "M_B_CPU1_SB_DQS_DP<1>")
	)
	(arc
		(start 84.66836 -233.017568)
		(mid 84.532241 -233.073969)
		(end 84.386166 -233.09326)
		(width 0.088646)
		(layer "In2.Cu")
		(net "M_B_CPU1_SB_DQS_DP<1>")
	)
	(arc
		(start 88.33231 -232.852722)
		(mid 88.207167 -232.904996)
		(end 88.072722 -232.922826)
		(width 0.088646)
		(layer "In2.Cu")
		(net "M_B_CPU1_SB_DQS_DP<1>")
	)
	(arc
		(start 85.043264 -233.017822)
		(mid 84.856066 -232.967679)
		(end 84.668868 -233.017822)
		(width 0.088646)
		(layer "In2.Cu")
		(net "M_B_CPU1_SB_DQS_DP<1>")
	)
	(arc
		(start 86.548468 -233.017822)
		(mid 86.265766 -233.093598)
		(end 85.983064 -233.017822)
		(width 0.088646)
		(layer "In2.Cu")
		(net "M_B_CPU1_SB_DQS_DP<1>")
	)
	(arc
		(start 85.983064 -233.017822)
		(mid 85.795866 -232.967679)
		(end 85.608668 -233.017822)
		(width 0.088646)
		(layer "In2.Cu")
		(net "M_B_CPU1_SB_DQS_DP<1>")
	)
	(segment
		(start 40.175688 -228.930708)
		(end 39.539672 -228.505512)
		(width 0.20066)
		(layer "F.Cu")
		(net "M_B_CPU1_SB_DQS_DP<0>")
	)
	(segment
		(start 41.29151 -229.201218)
		(end 41.073324 -229.201218)
		(width 0.20066)
		(layer "F.Cu")
		(net "M_B_CPU1_SB_DQS_DP<0>")
	)
	(segment
		(start 43.293284 -229.19182)
		(end 41.53789 -229.19182)
		(width 0.1016)
		(layer "F.Cu")
		(net "M_B_CPU1_SB_DQS_DP<0>")
	)
	(segment
		(start 45.049694 -228.505512)
		(end 44.780962 -228.505512)
		(width 0.20066)
		(layer "F.Cu")
		(net "M_B_CPU1_SB_DQS_DP<0>")
	)
	(segment
		(start 41.300908 -229.19182)
		(end 41.29151 -229.201218)
		(width 0.101854)
		(layer "F.Cu")
		(net "M_B_CPU1_SB_DQS_DP<0>")
	)
	(segment
		(start 92.374466 -235.506006)
		(end 92.374466 -234.97032)
		(width 0.20066)
		(layer "F.Cu")
		(net "M_B_CPU1_SB_DQS_DP<0>")
	)
	(segment
		(start 39.539672 -228.505512)
		(end 39.11473 -228.505512)
		(width 0.20066)
		(layer "F.Cu")
		(net "M_B_CPU1_SB_DQS_DP<0>")
	)
	(segment
		(start 92.374466 -234.97032)
		(end 92.374212 -234.970066)
		(width 0.20066)
		(layer "F.Cu")
		(net "M_B_CPU1_SB_DQS_DP<0>")
	)
	(segment
		(start 44.355766 -228.930708)
		(end 44.029884 -228.930708)
		(width 0.20066)
		(layer "F.Cu")
		(net "M_B_CPU1_SB_DQS_DP<0>")
	)
	(segment
		(start 38.853618 -228.766624)
		(end 38.315646 -228.766624)
		(width 0.20066)
		(layer "F.Cu")
		(net "M_B_CPU1_SB_DQS_DP<0>")
	)
	(segment
		(start 45.859446 -228.766624)
		(end 45.310806 -228.766624)
		(width 0.20066)
		(layer "F.Cu")
		(net "M_B_CPU1_SB_DQS_DP<0>")
	)
	(segment
		(start 45.310806 -228.766624)
		(end 45.049694 -228.505512)
		(width 0.20066)
		(layer "F.Cu")
		(net "M_B_CPU1_SB_DQS_DP<0>")
	)
	(segment
		(start 46.964346 -228.766624)
		(end 45.859446 -228.766624)
		(width 0.20066)
		(layer "F.Cu")
		(net "M_B_CPU1_SB_DQS_DP<0>")
	)
	(segment
		(start 41.073324 -229.201218)
		(end 40.802814 -228.930708)
		(width 0.20066)
		(layer "F.Cu")
		(net "M_B_CPU1_SB_DQS_DP<0>")
	)
	(segment
		(start 43.768772 -229.19182)
		(end 43.616626 -229.19182)
		(width 0.20066)
		(layer "F.Cu")
		(net "M_B_CPU1_SB_DQS_DP<0>")
	)
	(segment
		(start 44.029884 -228.930708)
		(end 43.768772 -229.19182)
		(width 0.20066)
		(layer "F.Cu")
		(net "M_B_CPU1_SB_DQS_DP<0>")
	)
	(segment
		(start 40.802814 -228.930708)
		(end 40.175688 -228.930708)
		(width 0.20066)
		(layer "F.Cu")
		(net "M_B_CPU1_SB_DQS_DP<0>")
	)
	(segment
		(start 44.780962 -228.505512)
		(end 44.355766 -228.930708)
		(width 0.20066)
		(layer "F.Cu")
		(net "M_B_CPU1_SB_DQS_DP<0>")
	)
	(segment
		(start 39.11473 -228.505512)
		(end 38.853618 -228.766624)
		(width 0.20066)
		(layer "F.Cu")
		(net "M_B_CPU1_SB_DQS_DP<0>")
	)
	(segment
		(start 43.616626 -229.19182)
		(end 43.293284 -229.19182)
		(width 0.101854)
		(layer "F.Cu")
		(net "M_B_CPU1_SB_DQS_DP<0>")
	)
	(segment
		(start 41.53789 -229.19182)
		(end 41.300908 -229.19182)
		(width 0.101854)
		(layer "F.Cu")
		(net "M_B_CPU1_SB_DQS_DP<0>")
	)
	(segment
		(start 62.530228 -227.211636)
		(end 62.25032 -227.491544)
		(width 0.18288)
		(layer "In4.Cu")
		(net "M_B_CPU1_SB_DQS_DP<0>")
	)
	(segment
		(start 84.230718 -235.408978)
		(end 84.15909 -235.480606)
		(width 0.088646)
		(layer "In4.Cu")
		(net "M_B_CPU1_SB_DQS_DP<0>")
	)
	(segment
		(start 85.527896 -235.46816)
		(end 85.513164 -235.459524)
		(width 0.088646)
		(layer "In4.Cu")
		(net "M_B_CPU1_SB_DQS_DP<0>")
	)
	(segment
		(start 63.389256 -227.211636)
		(end 62.530228 -227.211636)
		(width 0.18288)
		(layer "In4.Cu")
		(net "M_B_CPU1_SB_DQS_DP<0>")
	)
	(segment
		(start 51.238404 -229.19182)
		(end 50.866548 -229.19182)
		(width 0.18288)
		(layer "In4.Cu")
		(net "M_B_CPU1_SB_DQS_DP<0>")
	)
	(segment
		(start 50.137568 -228.955854)
		(end 49.436782 -228.255068)
		(width 0.18288)
		(layer "In4.Cu")
		(net "M_B_CPU1_SB_DQS_DP<0>")
	)
	(segment
		(start 47.569882 -228.485192)
		(end 47.245778 -228.485192)
		(width 0.18288)
		(layer "In4.Cu")
		(net "M_B_CPU1_SB_DQS_DP<0>")
	)
	(segment
		(start 90.98661 -235.339128)
		(end 90.76309 -235.467906)
		(width 0.088646)
		(layer "In4.Cu")
		(net "M_B_CPU1_SB_DQS_DP<0>")
	)
	(segment
		(start 51.656996 -228.651562)
		(end 51.500024 -228.808534)
		(width 0.18288)
		(layer "In4.Cu")
		(net "M_B_CPU1_SB_DQS_DP<0>")
	)
	(segment
		(start 51.500024 -228.808534)
		(end 51.500024 -228.9302)
		(width 0.18288)
		(layer "In4.Cu")
		(net "M_B_CPU1_SB_DQS_DP<0>")
	)
	(segment
		(start 88.347296 -235.46816)
		(end 88.332564 -235.459524)
		(width 0.088646)
		(layer "In4.Cu")
		(net "M_B_CPU1_SB_DQS_DP<0>")
	)
	(segment
		(start 60.38977 -226.569778)
		(end 59.321954 -226.569778)
		(width 0.18288)
		(layer "In4.Cu")
		(net "M_B_CPU1_SB_DQS_DP<0>")
	)
	(segment
		(start 47.245778 -228.485192)
		(end 46.964346 -228.766624)
		(width 0.18288)
		(layer "In4.Cu")
		(net "M_B_CPU1_SB_DQS_DP<0>")
	)
	(segment
		(start 67.448176 -228.899974)
		(end 66.61531 -228.899974)
		(width 0.18288)
		(layer "In4.Cu")
		(net "M_B_CPU1_SB_DQS_DP<0>")
	)
	(segment
		(start 57.17032 -228.156516)
		(end 53.694838 -228.156516)
		(width 0.18288)
		(layer "In4.Cu")
		(net "M_B_CPU1_SB_DQS_DP<0>")
	)
	(segment
		(start 91.34221 -235.339128)
		(end 90.98661 -235.339128)
		(width 0.088646)
		(layer "In4.Cu")
		(net "M_B_CPU1_SB_DQS_DP<0>")
	)
	(segment
		(start 65.954148 -229.19182)
		(end 65.659762 -228.897434)
		(width 0.18288)
		(layer "In4.Cu")
		(net "M_B_CPU1_SB_DQS_DP<0>")
	)
	(segment
		(start 66.61531 -228.899974)
		(end 66.323464 -229.19182)
		(width 0.18288)
		(layer "In4.Cu")
		(net "M_B_CPU1_SB_DQS_DP<0>")
	)
	(segment
		(start 49.436782 -228.255068)
		(end 47.800006 -228.255068)
		(width 0.18288)
		(layer "In4.Cu")
		(net "M_B_CPU1_SB_DQS_DP<0>")
	)
	(segment
		(start 50.866548 -229.19182)
		(end 50.630582 -228.955854)
		(width 0.18288)
		(layer "In4.Cu")
		(net "M_B_CPU1_SB_DQS_DP<0>")
	)
	(segment
		(start 66.323464 -229.19182)
		(end 65.954148 -229.19182)
		(width 0.18288)
		(layer "In4.Cu")
		(net "M_B_CPU1_SB_DQS_DP<0>")
	)
	(segment
		(start 82.708496 -235.54055)
		(end 74.088752 -235.54055)
		(width 0.18288)
		(layer "In4.Cu")
		(net "M_B_CPU1_SB_DQS_DP<0>")
	)
	(segment
		(start 84.385912 -235.408978)
		(end 84.230718 -235.408978)
		(width 0.088646)
		(layer "In4.Cu")
		(net "M_B_CPU1_SB_DQS_DP<0>")
	)
	(segment
		(start 53.694838 -228.156516)
		(end 53.199792 -228.651562)
		(width 0.18288)
		(layer "In4.Cu")
		(net "M_B_CPU1_SB_DQS_DP<0>")
	)
	(segment
		(start 47.800006 -228.255068)
		(end 47.569882 -228.485192)
		(width 0.18288)
		(layer "In4.Cu")
		(net "M_B_CPU1_SB_DQS_DP<0>")
	)
	(segment
		(start 87.407496 -235.46816)
		(end 87.392764 -235.459524)
		(width 0.088646)
		(layer "In4.Cu")
		(net "M_B_CPU1_SB_DQS_DP<0>")
	)
	(segment
		(start 91.404186 -235.343446)
		(end 91.347036 -235.336588)
		(width 0.088646)
		(layer "In4.Cu")
		(net "M_B_CPU1_SB_DQS_DP<0>")
	)
	(segment
		(start 61.036962 -227.21697)
		(end 60.38977 -226.569778)
		(width 0.18288)
		(layer "In4.Cu")
		(net "M_B_CPU1_SB_DQS_DP<0>")
	)
	(segment
		(start 65.075054 -228.897434)
		(end 63.389256 -227.211636)
		(width 0.18288)
		(layer "In4.Cu")
		(net "M_B_CPU1_SB_DQS_DP<0>")
	)
	(segment
		(start 53.199792 -228.651562)
		(end 51.656996 -228.651562)
		(width 0.18288)
		(layer "In4.Cu")
		(net "M_B_CPU1_SB_DQS_DP<0>")
	)
	(segment
		(start 61.58103 -227.21697)
		(end 61.036962 -227.21697)
		(width 0.18288)
		(layer "In4.Cu")
		(net "M_B_CPU1_SB_DQS_DP<0>")
	)
	(segment
		(start 50.630582 -228.955854)
		(end 50.137568 -228.955854)
		(width 0.18288)
		(layer "In4.Cu")
		(net "M_B_CPU1_SB_DQS_DP<0>")
	)
	(segment
		(start 92.033852 -235.059982)
		(end 91.608656 -235.30179)
		(width 0.088646)
		(layer "In4.Cu")
		(net "M_B_CPU1_SB_DQS_DP<0>")
	)
	(segment
		(start 86.467696 -235.46816)
		(end 86.452964 -235.459524)
		(width 0.088646)
		(layer "In4.Cu")
		(net "M_B_CPU1_SB_DQS_DP<0>")
	)
	(segment
		(start 89.287096 -235.46816)
		(end 89.272364 -235.459524)
		(width 0.088646)
		(layer "In4.Cu")
		(net "M_B_CPU1_SB_DQS_DP<0>")
	)
	(segment
		(start 82.812128 -235.480606)
		(end 82.752184 -235.54055)
		(width 0.088646)
		(layer "In4.Cu")
		(net "M_B_CPU1_SB_DQS_DP<0>")
	)
	(segment
		(start 90.21191 -235.459524)
		(end 90.212164 -235.459524)
		(width 0.088646)
		(layer "In4.Cu")
		(net "M_B_CPU1_SB_DQS_DP<0>")
	)
	(segment
		(start 65.659762 -228.897434)
		(end 65.075054 -228.897434)
		(width 0.18288)
		(layer "In4.Cu")
		(net "M_B_CPU1_SB_DQS_DP<0>")
	)
	(segment
		(start 61.855604 -227.491544)
		(end 61.58103 -227.21697)
		(width 0.18288)
		(layer "In4.Cu")
		(net "M_B_CPU1_SB_DQS_DP<0>")
	)
	(segment
		(start 59.321954 -226.569778)
		(end 58.933588 -226.958144)
		(width 0.18288)
		(layer "In4.Cu")
		(net "M_B_CPU1_SB_DQS_DP<0>")
	)
	(segment
		(start 84.15909 -235.480606)
		(end 82.812128 -235.480606)
		(width 0.088646)
		(layer "In4.Cu")
		(net "M_B_CPU1_SB_DQS_DP<0>")
	)
	(segment
		(start 91.347036 -235.336588)
		(end 91.34221 -235.339128)
		(width 0.088646)
		(layer "In4.Cu")
		(net "M_B_CPU1_SB_DQS_DP<0>")
	)
	(segment
		(start 82.752184 -235.54055)
		(end 82.708496 -235.54055)
		(width 0.088646)
		(layer "In4.Cu")
		(net "M_B_CPU1_SB_DQS_DP<0>")
	)
	(segment
		(start 58.933588 -226.958144)
		(end 58.368692 -226.958144)
		(width 0.18288)
		(layer "In4.Cu")
		(net "M_B_CPU1_SB_DQS_DP<0>")
	)
	(segment
		(start 51.500024 -228.9302)
		(end 51.238404 -229.19182)
		(width 0.18288)
		(layer "In4.Cu")
		(net "M_B_CPU1_SB_DQS_DP<0>")
	)
	(segment
		(start 74.088752 -235.54055)
		(end 67.448176 -228.899974)
		(width 0.18288)
		(layer "In4.Cu")
		(net "M_B_CPU1_SB_DQS_DP<0>")
	)
	(segment
		(start 58.368692 -226.958144)
		(end 57.17032 -228.156516)
		(width 0.18288)
		(layer "In4.Cu")
		(net "M_B_CPU1_SB_DQS_DP<0>")
	)
	(segment
		(start 62.25032 -227.491544)
		(end 61.855604 -227.491544)
		(width 0.18288)
		(layer "In4.Cu")
		(net "M_B_CPU1_SB_DQS_DP<0>")
	)
	(arc
		(start 87.018368 -235.459524)
		(mid 86.744169 -235.535359)
		(end 86.467696 -235.46816)
		(width 0.088646)
		(layer "In4.Cu")
		(net "M_B_CPU1_SB_DQS_DP<0>")
	)
	(arc
		(start 90.76309 -235.467906)
		(mid 90.486425 -235.535377)
		(end 90.21191 -235.459524)
		(width 0.088646)
		(layer "In4.Cu")
		(net "M_B_CPU1_SB_DQS_DP<0>")
	)
	(arc
		(start 90.212164 -235.459524)
		(mid 90.024966 -235.409381)
		(end 89.837768 -235.459524)
		(width 0.088646)
		(layer "In4.Cu")
		(net "M_B_CPU1_SB_DQS_DP<0>")
	)
	(arc
		(start 88.897968 -235.459524)
		(mid 88.623769 -235.535359)
		(end 88.347296 -235.46816)
		(width 0.088646)
		(layer "In4.Cu")
		(net "M_B_CPU1_SB_DQS_DP<0>")
	)
	(arc
		(start 86.452964 -235.459524)
		(mid 86.265766 -235.409381)
		(end 86.078568 -235.459524)
		(width 0.088646)
		(layer "In4.Cu")
		(net "M_B_CPU1_SB_DQS_DP<0>")
	)
	(arc
		(start 88.332564 -235.459524)
		(mid 88.145366 -235.409381)
		(end 87.958168 -235.459524)
		(width 0.088646)
		(layer "In4.Cu")
		(net "M_B_CPU1_SB_DQS_DP<0>")
	)
	(arc
		(start 84.588096 -235.46816)
		(mid 84.491236 -235.424131)
		(end 84.385912 -235.408978)
		(width 0.088646)
		(layer "In4.Cu")
		(net "M_B_CPU1_SB_DQS_DP<0>")
	)
	(arc
		(start 89.837768 -235.459524)
		(mid 89.563569 -235.535359)
		(end 89.287096 -235.46816)
		(width 0.088646)
		(layer "In4.Cu")
		(net "M_B_CPU1_SB_DQS_DP<0>")
	)
	(arc
		(start 86.078568 -235.459524)
		(mid 85.804369 -235.535359)
		(end 85.527896 -235.46816)
		(width 0.088646)
		(layer "In4.Cu")
		(net "M_B_CPU1_SB_DQS_DP<0>")
	)
	(arc
		(start 92.374212 -234.970066)
		(mid 92.198191 -234.992903)
		(end 92.033852 -235.059982)
		(width 0.088646)
		(layer "In4.Cu")
		(net "M_B_CPU1_SB_DQS_DP<0>")
	)
	(arc
		(start 91.608656 -235.30179)
		(mid 91.509814 -235.3393)
		(end 91.404186 -235.343446)
		(width 0.088646)
		(layer "In4.Cu")
		(net "M_B_CPU1_SB_DQS_DP<0>")
	)
	(arc
		(start 87.392764 -235.459524)
		(mid 87.205566 -235.409381)
		(end 87.018368 -235.459524)
		(width 0.088646)
		(layer "In4.Cu")
		(net "M_B_CPU1_SB_DQS_DP<0>")
	)
	(arc
		(start 87.958168 -235.459524)
		(mid 87.683969 -235.535359)
		(end 87.407496 -235.46816)
		(width 0.088646)
		(layer "In4.Cu")
		(net "M_B_CPU1_SB_DQS_DP<0>")
	)
	(arc
		(start 85.138768 -235.459524)
		(mid 84.864569 -235.535359)
		(end 84.588096 -235.46816)
		(width 0.088646)
		(layer "In4.Cu")
		(net "M_B_CPU1_SB_DQS_DP<0>")
	)
	(arc
		(start 85.513164 -235.459524)
		(mid 85.325966 -235.409381)
		(end 85.138768 -235.459524)
		(width 0.088646)
		(layer "In4.Cu")
		(net "M_B_CPU1_SB_DQS_DP<0>")
	)
	(arc
		(start 89.272364 -235.459524)
		(mid 89.085166 -235.409381)
		(end 88.897968 -235.459524)
		(width 0.088646)
		(layer "In4.Cu")
		(net "M_B_CPU1_SB_DQS_DP<0>")
	)
	(segment
		(start 46.964346 -237.266734)
		(end 45.859446 -237.266734)
		(width 0.20066)
		(layer "F.Cu")
		(net "M_B_CPU1_SB_DQS_DN<9>")
	)
	(segment
		(start 89.084912 -242.830858)
		(end 89.085166 -242.830604)
		(width 0.20066)
		(layer "F.Cu")
		(net "M_B_CPU1_SB_DQS_DN<9>")
	)
	(segment
		(start 40.275256 -237.953042)
		(end 39.63924 -237.527846)
		(width 0.20066)
		(layer "F.Cu")
		(net "M_B_CPU1_SB_DQS_DN<9>")
	)
	(segment
		(start 45.312838 -237.266734)
		(end 45.051726 -237.527846)
		(width 0.20066)
		(layer "F.Cu")
		(net "M_B_CPU1_SB_DQS_DN<9>")
	)
	(segment
		(start 43.77182 -237.691676)
		(end 43.616626 -237.691676)
		(width 0.20066)
		(layer "F.Cu")
		(net "M_B_CPU1_SB_DQS_DN<9>")
	)
	(segment
		(start 41.087294 -237.681008)
		(end 40.81526 -237.953042)
		(width 0.20066)
		(layer "F.Cu")
		(net "M_B_CPU1_SB_DQS_DN<9>")
	)
	(segment
		(start 39.63924 -237.527846)
		(end 39.125398 -237.527846)
		(width 0.20066)
		(layer "F.Cu")
		(net "M_B_CPU1_SB_DQS_DN<9>")
	)
	(segment
		(start 45.859446 -237.266734)
		(end 45.312838 -237.266734)
		(width 0.20066)
		(layer "F.Cu")
		(net "M_B_CPU1_SB_DQS_DN<9>")
	)
	(segment
		(start 44.645072 -237.527846)
		(end 44.219876 -237.953042)
		(width 0.20066)
		(layer "F.Cu")
		(net "M_B_CPU1_SB_DQS_DN<9>")
	)
	(segment
		(start 44.219876 -237.953042)
		(end 44.033186 -237.953042)
		(width 0.20066)
		(layer "F.Cu")
		(net "M_B_CPU1_SB_DQS_DN<9>")
	)
	(segment
		(start 41.292272 -237.681008)
		(end 41.29151 -237.681008)
		(width 0.101854)
		(layer "F.Cu")
		(net "M_B_CPU1_SB_DQS_DN<9>")
	)
	(segment
		(start 43.616626 -237.691676)
		(end 41.30294 -237.691676)
		(width 0.1016)
		(layer "F.Cu")
		(net "M_B_CPU1_SB_DQS_DN<9>")
	)
	(segment
		(start 41.29151 -237.681008)
		(end 41.087294 -237.681008)
		(width 0.20066)
		(layer "F.Cu")
		(net "M_B_CPU1_SB_DQS_DN<9>")
	)
	(segment
		(start 40.81526 -237.953042)
		(end 40.275256 -237.953042)
		(width 0.20066)
		(layer "F.Cu")
		(net "M_B_CPU1_SB_DQS_DN<9>")
	)
	(segment
		(start 45.051726 -237.527846)
		(end 44.645072 -237.527846)
		(width 0.20066)
		(layer "F.Cu")
		(net "M_B_CPU1_SB_DQS_DN<9>")
	)
	(segment
		(start 89.085166 -242.830604)
		(end 89.085166 -242.294918)
		(width 0.20066)
		(layer "F.Cu")
		(net "M_B_CPU1_SB_DQS_DN<9>")
	)
	(segment
		(start 39.125398 -237.527846)
		(end 38.864286 -237.266734)
		(width 0.20066)
		(layer "F.Cu")
		(net "M_B_CPU1_SB_DQS_DN<9>")
	)
	(segment
		(start 44.033186 -237.953042)
		(end 43.77182 -237.691676)
		(width 0.20066)
		(layer "F.Cu")
		(net "M_B_CPU1_SB_DQS_DN<9>")
	)
	(segment
		(start 41.30294 -237.691676)
		(end 41.292272 -237.681008)
		(width 0.101854)
		(layer "F.Cu")
		(net "M_B_CPU1_SB_DQS_DN<9>")
	)
	(segment
		(start 38.864286 -237.266734)
		(end 38.315646 -237.266734)
		(width 0.20066)
		(layer "F.Cu")
		(net "M_B_CPU1_SB_DQS_DN<9>")
	)
	(segment
		(start 54.576472 -235.203238)
		(end 54.37632 -235.003086)
		(width 0.16002)
		(layer "In2.Cu")
		(net "M_B_CPU1_SB_DQS_DN<9>")
	)
	(segment
		(start 54.59222 -235.203238)
		(end 54.576472 -235.203238)
		(width 0.16002)
		(layer "In2.Cu")
		(net "M_B_CPU1_SB_DQS_DN<9>")
	)
	(segment
		(start 75.494134 -241.866166)
		(end 72.0217 -238.393732)
		(width 0.18288)
		(layer "In2.Cu")
		(net "M_B_CPU1_SB_DQS_DN<9>")
	)
	(segment
		(start 62.751716 -236.232954)
		(end 62.476888 -235.958126)
		(width 0.18288)
		(layer "In2.Cu")
		(net "M_B_CPU1_SB_DQS_DN<9>")
	)
	(segment
		(start 52.430172 -234.987338)
		(end 52.430172 -235.003086)
		(width 0.16002)
		(layer "In2.Cu")
		(net "M_B_CPU1_SB_DQS_DN<9>")
	)
	(segment
		(start 60.326016 -236.232954)
		(end 60.051188 -235.958126)
		(width 0.18288)
		(layer "In2.Cu")
		(net "M_B_CPU1_SB_DQS_DN<9>")
	)
	(segment
		(start 65.989708 -235.82249)
		(end 65.989708 -235.806742)
		(width 0.16002)
		(layer "In2.Cu")
		(net "M_B_CPU1_SB_DQS_DN<9>")
	)
	(segment
		(start 49.1109 -235.71327)
		(end 48.910748 -235.913422)
		(width 0.16002)
		(layer "In2.Cu")
		(net "M_B_CPU1_SB_DQS_DN<9>")
	)
	(segment
		(start 89.072212 -242.281964)
		(end 88.361774 -241.987578)
		(width 0.088646)
		(layer "In2.Cu")
		(net "M_B_CPU1_SB_DQS_DN<9>")
	)
	(segment
		(start 50.871374 -235.138468)
		(end 50.600864 -235.408978)
		(width 0.18288)
		(layer "In2.Cu")
		(net "M_B_CPU1_SB_DQS_DN<9>")
	)
	(segment
		(start 52.001674 -235.415836)
		(end 51.524408 -235.415836)
		(width 0.18288)
		(layer "In2.Cu")
		(net "M_B_CPU1_SB_DQS_DN<9>")
	)
	(segment
		(start 62.088522 -235.958126)
		(end 61.813694 -236.232954)
		(width 0.18288)
		(layer "In2.Cu")
		(net "M_B_CPU1_SB_DQS_DN<9>")
	)
	(segment
		(start 83.87715 -241.92611)
		(end 83.12404 -241.92611)
		(width 0.088646)
		(layer "In2.Cu")
		(net "M_B_CPU1_SB_DQS_DN<9>")
	)
	(segment
		(start 52.23002 -235.203238)
		(end 52.214272 -235.203238)
		(width 0.16002)
		(layer "In2.Cu")
		(net "M_B_CPU1_SB_DQS_DN<9>")
	)
	(segment
		(start 54.183534 -234.794552)
		(end 52.622958 -234.794552)
		(width 0.18288)
		(layer "In2.Cu")
		(net "M_B_CPU1_SB_DQS_DN<9>")
	)
	(segment
		(start 48.866806 -235.941616)
		(end 48.597312 -236.21111)
		(width 0.18288)
		(layer "In2.Cu")
		(net "M_B_CPU1_SB_DQS_DN<9>")
	)
	(segment
		(start 64.07404 -235.837222)
		(end 64.07404 -235.85297)
		(width 0.16002)
		(layer "In2.Cu")
		(net "M_B_CPU1_SB_DQS_DN<9>")
	)
	(segment
		(start 61.813694 -236.232954)
		(end 60.326016 -236.232954)
		(width 0.18288)
		(layer "In2.Cu")
		(net "M_B_CPU1_SB_DQS_DN<9>")
	)
	(segment
		(start 66.391536 -236.20857)
		(end 66.233802 -236.050836)
		(width 0.18288)
		(layer "In2.Cu")
		(net "M_B_CPU1_SB_DQS_DN<9>")
	)
	(segment
		(start 72.0217 -238.393732)
		(end 67.180714 -236.386878)
		(width 0.18288)
		(layer "In2.Cu")
		(net "M_B_CPU1_SB_DQS_DN<9>")
	)
	(segment
		(start 56.61914 -235.74121)
		(end 56.418988 -235.941362)
		(width 0.16002)
		(layer "In2.Cu")
		(net "M_B_CPU1_SB_DQS_DN<9>")
	)
	(segment
		(start 88.361774 -241.987578)
		(end 88.332564 -241.97056)
		(width 0.088646)
		(layer "In2.Cu")
		(net "M_B_CPU1_SB_DQS_DN<9>")
	)
	(segment
		(start 66.233802 -236.050836)
		(end 66.205608 -236.022642)
		(width 0.16002)
		(layer "In2.Cu")
		(net "M_B_CPU1_SB_DQS_DN<9>")
	)
	(segment
		(start 87.564214 -241.858038)
		(end 87.554562 -241.84991)
		(width 0.088646)
		(layer "In2.Cu")
		(net "M_B_CPU1_SB_DQS_DN<9>")
	)
	(segment
		(start 47.620174 -237.498636)
		(end 47.196248 -237.498636)
		(width 0.18288)
		(layer "In2.Cu")
		(net "M_B_CPU1_SB_DQS_DN<9>")
	)
	(segment
		(start 48.597312 -236.21111)
		(end 48.597312 -236.521498)
		(width 0.18288)
		(layer "In2.Cu")
		(net "M_B_CPU1_SB_DQS_DN<9>")
	)
	(segment
		(start 58.67654 -236.053122)
		(end 58.476388 -235.85297)
		(width 0.16002)
		(layer "In2.Cu")
		(net "M_B_CPU1_SB_DQS_DN<9>")
	)
	(segment
		(start 58.476388 -235.837222)
		(end 58.448194 -235.809028)
		(width 0.16002)
		(layer "In2.Cu")
		(net "M_B_CPU1_SB_DQS_DN<9>")
	)
	(segment
		(start 62.476888 -235.958126)
		(end 62.088522 -235.958126)
		(width 0.18288)
		(layer "In2.Cu")
		(net "M_B_CPU1_SB_DQS_DN<9>")
	)
	(segment
		(start 65.989708 -235.806742)
		(end 65.961514 -235.778548)
		(width 0.16002)
		(layer "In2.Cu")
		(net "M_B_CPU1_SB_DQS_DN<9>")
	)
	(segment
		(start 67.180714 -236.386878)
		(end 66.675 -236.20857)
		(width 0.18288)
		(layer "In2.Cu")
		(net "M_B_CPU1_SB_DQS_DN<9>")
	)
	(segment
		(start 59.662822 -235.958126)
		(end 59.386978 -236.23397)
		(width 0.18288)
		(layer "In2.Cu")
		(net "M_B_CPU1_SB_DQS_DN<9>")
	)
	(segment
		(start 55.073296 -235.68406)
		(end 54.620414 -235.231432)
		(width 0.18288)
		(layer "In2.Cu")
		(net "M_B_CPU1_SB_DQS_DN<9>")
	)
	(segment
		(start 87.564722 -241.858292)
		(end 87.564214 -241.858038)
		(width 0.088646)
		(layer "In2.Cu")
		(net "M_B_CPU1_SB_DQS_DN<9>")
	)
	(segment
		(start 48.910748 -235.913422)
		(end 48.895 -235.913422)
		(width 0.16002)
		(layer "In2.Cu")
		(net "M_B_CPU1_SB_DQS_DN<9>")
	)
	(segment
		(start 83.064096 -241.866166)
		(end 75.494134 -241.866166)
		(width 0.18288)
		(layer "In2.Cu")
		(net "M_B_CPU1_SB_DQS_DN<9>")
	)
	(segment
		(start 48.597312 -236.521498)
		(end 47.620174 -237.498636)
		(width 0.18288)
		(layer "In2.Cu")
		(net "M_B_CPU1_SB_DQS_DN<9>")
	)
	(segment
		(start 49.399444 -235.408978)
		(end 49.139094 -235.669328)
		(width 0.18288)
		(layer "In2.Cu")
		(net "M_B_CPU1_SB_DQS_DN<9>")
	)
	(segment
		(start 52.458366 -234.959144)
		(end 52.430172 -234.987338)
		(width 0.16002)
		(layer "In2.Cu")
		(net "M_B_CPU1_SB_DQS_DN<9>")
	)
	(segment
		(start 87.530432 -241.829844)
		(end 87.488268 -241.80546)
		(width 0.088646)
		(layer "In2.Cu")
		(net "M_B_CPU1_SB_DQS_DN<9>")
	)
	(segment
		(start 58.692288 -236.053122)
		(end 58.67654 -236.053122)
		(width 0.16002)
		(layer "In2.Cu")
		(net "M_B_CPU1_SB_DQS_DN<9>")
	)
	(segment
		(start 56.375046 -235.969556)
		(end 56.283352 -236.06125)
		(width 0.18288)
		(layer "In2.Cu")
		(net "M_B_CPU1_SB_DQS_DN<9>")
	)
	(segment
		(start 49.1109 -235.697522)
		(end 49.1109 -235.71327)
		(width 0.16002)
		(layer "In2.Cu")
		(net "M_B_CPU1_SB_DQS_DN<9>")
	)
	(segment
		(start 66.18986 -236.022642)
		(end 65.989708 -235.82249)
		(width 0.16002)
		(layer "In2.Cu")
		(net "M_B_CPU1_SB_DQS_DN<9>")
	)
	(segment
		(start 52.622958 -234.794552)
		(end 52.458366 -234.959144)
		(width 0.18288)
		(layer "In2.Cu")
		(net "M_B_CPU1_SB_DQS_DN<9>")
	)
	(segment
		(start 54.37632 -235.003086)
		(end 54.37632 -234.987338)
		(width 0.16002)
		(layer "In2.Cu")
		(net "M_B_CPU1_SB_DQS_DN<9>")
	)
	(segment
		(start 58.476388 -235.85297)
		(end 58.476388 -235.837222)
		(width 0.16002)
		(layer "In2.Cu")
		(net "M_B_CPU1_SB_DQS_DN<9>")
	)
	(segment
		(start 65.81013 -235.627164)
		(end 64.284098 -235.627164)
		(width 0.18288)
		(layer "In2.Cu")
		(net "M_B_CPU1_SB_DQS_DN<9>")
	)
	(segment
		(start 56.283352 -236.06125)
		(end 55.983378 -236.06125)
		(width 0.18288)
		(layer "In2.Cu")
		(net "M_B_CPU1_SB_DQS_DN<9>")
	)
	(segment
		(start 56.40324 -235.941362)
		(end 56.375046 -235.969556)
		(width 0.16002)
		(layer "In2.Cu")
		(net "M_B_CPU1_SB_DQS_DN<9>")
	)
	(segment
		(start 83.12404 -241.92611)
		(end 83.064096 -241.866166)
		(width 0.088646)
		(layer "In2.Cu")
		(net "M_B_CPU1_SB_DQS_DN<9>")
	)
	(segment
		(start 66.675 -236.20857)
		(end 66.391536 -236.20857)
		(width 0.18288)
		(layer "In2.Cu")
		(net "M_B_CPU1_SB_DQS_DN<9>")
	)
	(segment
		(start 65.961514 -235.778548)
		(end 65.81013 -235.627164)
		(width 0.18288)
		(layer "In2.Cu")
		(net "M_B_CPU1_SB_DQS_DN<9>")
	)
	(segment
		(start 58.126376 -235.48721)
		(end 56.857392 -235.48721)
		(width 0.18288)
		(layer "In2.Cu")
		(net "M_B_CPU1_SB_DQS_DN<9>")
	)
	(segment
		(start 58.873136 -236.23397)
		(end 58.720482 -236.081316)
		(width 0.18288)
		(layer "In2.Cu")
		(net "M_B_CPU1_SB_DQS_DN<9>")
	)
	(segment
		(start 60.051188 -235.958126)
		(end 59.662822 -235.958126)
		(width 0.18288)
		(layer "In2.Cu")
		(net "M_B_CPU1_SB_DQS_DN<9>")
	)
	(segment
		(start 84.073492 -241.729768)
		(end 83.87715 -241.92611)
		(width 0.088646)
		(layer "In2.Cu")
		(net "M_B_CPU1_SB_DQS_DN<9>")
	)
	(segment
		(start 56.418988 -235.941362)
		(end 56.40324 -235.941362)
		(width 0.16002)
		(layer "In2.Cu")
		(net "M_B_CPU1_SB_DQS_DN<9>")
	)
	(segment
		(start 63.85814 -236.053122)
		(end 63.829946 -236.081316)
		(width 0.16002)
		(layer "In2.Cu")
		(net "M_B_CPU1_SB_DQS_DN<9>")
	)
	(segment
		(start 59.386978 -236.23397)
		(end 58.873136 -236.23397)
		(width 0.18288)
		(layer "In2.Cu")
		(net "M_B_CPU1_SB_DQS_DN<9>")
	)
	(segment
		(start 89.085166 -242.294918)
		(end 89.072212 -242.281964)
		(width 0.088646)
		(layer "In2.Cu")
		(net "M_B_CPU1_SB_DQS_DN<9>")
	)
	(segment
		(start 64.102234 -235.809028)
		(end 64.07404 -235.837222)
		(width 0.16002)
		(layer "In2.Cu")
		(net "M_B_CPU1_SB_DQS_DN<9>")
	)
	(segment
		(start 49.139094 -235.669328)
		(end 49.1109 -235.697522)
		(width 0.16002)
		(layer "In2.Cu")
		(net "M_B_CPU1_SB_DQS_DN<9>")
	)
	(segment
		(start 56.647334 -235.697268)
		(end 56.61914 -235.725462)
		(width 0.16002)
		(layer "In2.Cu")
		(net "M_B_CPU1_SB_DQS_DN<9>")
	)
	(segment
		(start 63.829946 -236.081316)
		(end 63.678308 -236.232954)
		(width 0.18288)
		(layer "In2.Cu")
		(net "M_B_CPU1_SB_DQS_DN<9>")
	)
	(segment
		(start 56.61914 -235.725462)
		(end 56.61914 -235.74121)
		(width 0.16002)
		(layer "In2.Cu")
		(net "M_B_CPU1_SB_DQS_DN<9>")
	)
	(segment
		(start 52.214272 -235.203238)
		(end 52.186078 -235.231432)
		(width 0.16002)
		(layer "In2.Cu")
		(net "M_B_CPU1_SB_DQS_DN<9>")
	)
	(segment
		(start 64.07404 -235.85297)
		(end 63.873888 -236.053122)
		(width 0.16002)
		(layer "In2.Cu")
		(net "M_B_CPU1_SB_DQS_DN<9>")
	)
	(segment
		(start 56.857392 -235.48721)
		(end 56.647334 -235.697268)
		(width 0.18288)
		(layer "In2.Cu")
		(net "M_B_CPU1_SB_DQS_DN<9>")
	)
	(segment
		(start 58.720482 -236.081316)
		(end 58.692288 -236.053122)
		(width 0.16002)
		(layer "In2.Cu")
		(net "M_B_CPU1_SB_DQS_DN<9>")
	)
	(segment
		(start 55.983378 -236.06125)
		(end 55.073296 -235.68406)
		(width 0.18288)
		(layer "In2.Cu")
		(net "M_B_CPU1_SB_DQS_DN<9>")
	)
	(segment
		(start 50.600864 -235.408978)
		(end 49.399444 -235.408978)
		(width 0.18288)
		(layer "In2.Cu")
		(net "M_B_CPU1_SB_DQS_DN<9>")
	)
	(segment
		(start 48.895 -235.913422)
		(end 48.866806 -235.941616)
		(width 0.16002)
		(layer "In2.Cu")
		(net "M_B_CPU1_SB_DQS_DN<9>")
	)
	(segment
		(start 54.37632 -234.987338)
		(end 54.348126 -234.959144)
		(width 0.16002)
		(layer "In2.Cu")
		(net "M_B_CPU1_SB_DQS_DN<9>")
	)
	(segment
		(start 51.24704 -235.138468)
		(end 50.871374 -235.138468)
		(width 0.18288)
		(layer "In2.Cu")
		(net "M_B_CPU1_SB_DQS_DN<9>")
	)
	(segment
		(start 85.608668 -241.80546)
		(end 85.608414 -241.80546)
		(width 0.088646)
		(layer "In2.Cu")
		(net "M_B_CPU1_SB_DQS_DN<9>")
	)
	(segment
		(start 86.937596 -241.796824)
		(end 86.922864 -241.80546)
		(width 0.088646)
		(layer "In2.Cu")
		(net "M_B_CPU1_SB_DQS_DN<9>")
	)
	(segment
		(start 52.430172 -235.003086)
		(end 52.23002 -235.203238)
		(width 0.16002)
		(layer "In2.Cu")
		(net "M_B_CPU1_SB_DQS_DN<9>")
	)
	(segment
		(start 88.072976 -241.900456)
		(end 87.68207 -241.900456)
		(width 0.088646)
		(layer "In2.Cu")
		(net "M_B_CPU1_SB_DQS_DN<9>")
	)
	(segment
		(start 64.284098 -235.627164)
		(end 64.102234 -235.809028)
		(width 0.18288)
		(layer "In2.Cu")
		(net "M_B_CPU1_SB_DQS_DN<9>")
	)
	(segment
		(start 54.620414 -235.231432)
		(end 54.59222 -235.203238)
		(width 0.16002)
		(layer "In2.Cu")
		(net "M_B_CPU1_SB_DQS_DN<9>")
	)
	(segment
		(start 54.348126 -234.959144)
		(end 54.183534 -234.794552)
		(width 0.18288)
		(layer "In2.Cu")
		(net "M_B_CPU1_SB_DQS_DN<9>")
	)
	(segment
		(start 52.186078 -235.231432)
		(end 52.001674 -235.415836)
		(width 0.18288)
		(layer "In2.Cu")
		(net "M_B_CPU1_SB_DQS_DN<9>")
	)
	(segment
		(start 63.678308 -236.232954)
		(end 62.751716 -236.232954)
		(width 0.18288)
		(layer "In2.Cu")
		(net "M_B_CPU1_SB_DQS_DN<9>")
	)
	(segment
		(start 47.196248 -237.498636)
		(end 46.964346 -237.266734)
		(width 0.18288)
		(layer "In2.Cu")
		(net "M_B_CPU1_SB_DQS_DN<9>")
	)
	(segment
		(start 87.554562 -241.84991)
		(end 87.530432 -241.829844)
		(width 0.088646)
		(layer "In2.Cu")
		(net "M_B_CPU1_SB_DQS_DN<9>")
	)
	(segment
		(start 51.524408 -235.415836)
		(end 51.24704 -235.138468)
		(width 0.18288)
		(layer "In2.Cu")
		(net "M_B_CPU1_SB_DQS_DN<9>")
	)
	(segment
		(start 84.386166 -241.729768)
		(end 84.073492 -241.729768)
		(width 0.088646)
		(layer "In2.Cu")
		(net "M_B_CPU1_SB_DQS_DN<9>")
	)
	(segment
		(start 58.448194 -235.809028)
		(end 58.126376 -235.48721)
		(width 0.18288)
		(layer "In2.Cu")
		(net "M_B_CPU1_SB_DQS_DN<9>")
	)
	(segment
		(start 66.205608 -236.022642)
		(end 66.18986 -236.022642)
		(width 0.16002)
		(layer "In2.Cu")
		(net "M_B_CPU1_SB_DQS_DN<9>")
	)
	(segment
		(start 63.873888 -236.053122)
		(end 63.85814 -236.053122)
		(width 0.16002)
		(layer "In2.Cu")
		(net "M_B_CPU1_SB_DQS_DN<9>")
	)
	(arc
		(start 84.668614 -241.80546)
		(mid 84.532368 -241.749051)
		(end 84.386166 -241.729768)
		(width 0.088646)
		(layer "In2.Cu")
		(net "M_B_CPU1_SB_DQS_DN<9>")
	)
	(arc
		(start 85.983064 -241.80546)
		(mid 85.795866 -241.855603)
		(end 85.608668 -241.80546)
		(width 0.088646)
		(layer "In2.Cu")
		(net "M_B_CPU1_SB_DQS_DN<9>")
	)
	(arc
		(start 85.608414 -241.80546)
		(mid 85.325712 -241.729684)
		(end 85.04301 -241.80546)
		(width 0.088646)
		(layer "In2.Cu")
		(net "M_B_CPU1_SB_DQS_DN<9>")
	)
	(arc
		(start 87.68207 -241.900456)
		(mid 87.619713 -241.889609)
		(end 87.564722 -241.858292)
		(width 0.088646)
		(layer "In2.Cu")
		(net "M_B_CPU1_SB_DQS_DN<9>")
	)
	(arc
		(start 88.332564 -241.97056)
		(mid 88.207421 -241.918286)
		(end 88.072976 -241.900456)
		(width 0.088646)
		(layer "In2.Cu")
		(net "M_B_CPU1_SB_DQS_DN<9>")
	)
	(arc
		(start 87.488268 -241.80546)
		(mid 87.214069 -241.729625)
		(end 86.937596 -241.796824)
		(width 0.088646)
		(layer "In2.Cu")
		(net "M_B_CPU1_SB_DQS_DN<9>")
	)
	(arc
		(start 86.548468 -241.80546)
		(mid 86.265766 -241.729684)
		(end 85.983064 -241.80546)
		(width 0.088646)
		(layer "In2.Cu")
		(net "M_B_CPU1_SB_DQS_DN<9>")
	)
	(arc
		(start 85.04301 -241.80546)
		(mid 84.855812 -241.855603)
		(end 84.668614 -241.80546)
		(width 0.088646)
		(layer "In2.Cu")
		(net "M_B_CPU1_SB_DQS_DN<9>")
	)
	(arc
		(start 86.922864 -241.80546)
		(mid 86.735666 -241.855603)
		(end 86.548468 -241.80546)
		(width 0.088646)
		(layer "In2.Cu")
		(net "M_B_CPU1_SB_DQS_DN<9>")
	)
	(segment
		(start 49.207928 -199.605646)
		(end 48.504348 -199.605646)
		(width 0.20066)
		(layer "F.Cu")
		(net "M_B_CPU1_SB_DQS_DN<8>")
	)
	(segment
		(start 44.55033 -199.44969)
		(end 44.283884 -199.183244)
		(width 0.20066)
		(layer "F.Cu")
		(net "M_B_CPU1_SB_DQS_DN<8>")
	)
	(segment
		(start 47.202598 -199.441816)
		(end 47.060358 -199.441816)
		(width 0.20066)
		(layer "F.Cu")
		(net "M_B_CPU1_SB_DQS_DN<8>")
	)
	(segment
		(start 51.064414 -199.866758)
		(end 49.959514 -199.866758)
		(width 0.20066)
		(layer "F.Cu")
		(net "M_B_CPU1_SB_DQS_DN<8>")
	)
	(segment
		(start 42.887392 -199.866758)
		(end 42.415714 -199.866758)
		(width 0.20066)
		(layer "F.Cu")
		(net "M_B_CPU1_SB_DQS_DN<8>")
	)
	(segment
		(start 43.621706 -199.605646)
		(end 43.148504 -199.605646)
		(width 0.20066)
		(layer "F.Cu")
		(net "M_B_CPU1_SB_DQS_DN<8>")
	)
	(segment
		(start 48.504348 -199.605646)
		(end 47.868332 -199.180704)
		(width 0.20066)
		(layer "F.Cu")
		(net "M_B_CPU1_SB_DQS_DN<8>")
	)
	(segment
		(start 44.283884 -199.183244)
		(end 44.044108 -199.183244)
		(width 0.20066)
		(layer "F.Cu")
		(net "M_B_CPU1_SB_DQS_DN<8>")
	)
	(segment
		(start 49.959514 -199.866758)
		(end 49.46904 -199.866758)
		(width 0.20066)
		(layer "F.Cu")
		(net "M_B_CPU1_SB_DQS_DN<8>")
	)
	(segment
		(start 86.735666 -225.739198)
		(end 86.735666 -225.203258)
		(width 0.20066)
		(layer "F.Cu")
		(net "M_B_CPU1_SB_DQS_DN<8>")
	)
	(segment
		(start 43.148504 -199.605646)
		(end 42.887392 -199.866758)
		(width 0.20066)
		(layer "F.Cu")
		(net "M_B_CPU1_SB_DQS_DN<8>")
	)
	(segment
		(start 47.868332 -199.180704)
		(end 47.46371 -199.180704)
		(width 0.20066)
		(layer "F.Cu")
		(net "M_B_CPU1_SB_DQS_DN<8>")
	)
	(segment
		(start 44.743116 -199.441816)
		(end 44.735242 -199.44969)
		(width 0.101854)
		(layer "F.Cu")
		(net "M_B_CPU1_SB_DQS_DN<8>")
	)
	(segment
		(start 47.060358 -199.441816)
		(end 44.982892 -199.441816)
		(width 0.1016)
		(layer "F.Cu")
		(net "M_B_CPU1_SB_DQS_DN<8>")
	)
	(segment
		(start 44.982892 -199.441816)
		(end 44.743116 -199.441816)
		(width 0.101854)
		(layer "F.Cu")
		(net "M_B_CPU1_SB_DQS_DN<8>")
	)
	(segment
		(start 49.46904 -199.866758)
		(end 49.207928 -199.605646)
		(width 0.20066)
		(layer "F.Cu")
		(net "M_B_CPU1_SB_DQS_DN<8>")
	)
	(segment
		(start 44.044108 -199.183244)
		(end 43.621706 -199.605646)
		(width 0.20066)
		(layer "F.Cu")
		(net "M_B_CPU1_SB_DQS_DN<8>")
	)
	(segment
		(start 44.735242 -199.44969)
		(end 44.55033 -199.44969)
		(width 0.20066)
		(layer "F.Cu")
		(net "M_B_CPU1_SB_DQS_DN<8>")
	)
	(segment
		(start 47.46371 -199.180704)
		(end 47.202598 -199.441816)
		(width 0.20066)
		(layer "F.Cu")
		(net "M_B_CPU1_SB_DQS_DN<8>")
	)
	(segment
		(start 59.435492 -198.591424)
		(end 59.086496 -198.94042)
		(width 0.18288)
		(layer "In4.Cu")
		(net "M_B_CPU1_SB_DQS_DN<8>")
	)
	(segment
		(start 61.174376 -198.715884)
		(end 60.625736 -198.715884)
		(width 0.18288)
		(layer "In4.Cu")
		(net "M_B_CPU1_SB_DQS_DN<8>")
	)
	(segment
		(start 83.798664 -223.317816)
		(end 83.798664 -223.197166)
		(width 0.088646)
		(layer "In4.Cu")
		(net "M_B_CPU1_SB_DQS_DN<8>")
	)
	(segment
		(start 63.057278 -199.00011)
		(end 62.648592 -198.591424)
		(width 0.18288)
		(layer "In4.Cu")
		(net "M_B_CPU1_SB_DQS_DN<8>")
	)
	(segment
		(start 82.791808 -222.51416)
		(end 82.731864 -222.574104)
		(width 0.088646)
		(layer "In4.Cu")
		(net "M_B_CPU1_SB_DQS_DN<8>")
	)
	(segment
		(start 64.421004 -199.12457)
		(end 63.872364 -199.12457)
		(width 0.18288)
		(layer "In4.Cu")
		(net "M_B_CPU1_SB_DQS_DN<8>")
	)
	(segment
		(start 62.648592 -198.591424)
		(end 61.298836 -198.591424)
		(width 0.18288)
		(layer "In4.Cu")
		(net "M_B_CPU1_SB_DQS_DN<8>")
	)
	(segment
		(start 51.658266 -199.593962)
		(end 51.33721 -199.593962)
		(width 0.18288)
		(layer "In4.Cu")
		(net "M_B_CPU1_SB_DQS_DN<8>")
	)
	(segment
		(start 55.986172 -198.94042)
		(end 55.120794 -199.805798)
		(width 0.18288)
		(layer "In4.Cu")
		(net "M_B_CPU1_SB_DQS_DN<8>")
	)
	(segment
		(start 55.120794 -199.805798)
		(end 51.870102 -199.805798)
		(width 0.18288)
		(layer "In4.Cu")
		(net "M_B_CPU1_SB_DQS_DN<8>")
	)
	(segment
		(start 85.043772 -224.8789)
		(end 85.043264 -224.8789)
		(width 0.088646)
		(layer "In4.Cu")
		(net "M_B_CPU1_SB_DQS_DN<8>")
	)
	(segment
		(start 60.501276 -198.591424)
		(end 59.435492 -198.591424)
		(width 0.18288)
		(layer "In4.Cu")
		(net "M_B_CPU1_SB_DQS_DN<8>")
	)
	(segment
		(start 63.747904 -199.00011)
		(end 63.057278 -199.00011)
		(width 0.18288)
		(layer "In4.Cu")
		(net "M_B_CPU1_SB_DQS_DN<8>")
	)
	(segment
		(start 64.545464 -199.00011)
		(end 64.421004 -199.12457)
		(width 0.18288)
		(layer "In4.Cu")
		(net "M_B_CPU1_SB_DQS_DN<8>")
	)
	(segment
		(start 65.094104 -199.00011)
		(end 64.545464 -199.00011)
		(width 0.18288)
		(layer "In4.Cu")
		(net "M_B_CPU1_SB_DQS_DN<8>")
	)
	(segment
		(start 85.042502 -224.878392)
		(end 85.037168 -224.875344)
		(width 0.088646)
		(layer "In4.Cu")
		(net "M_B_CPU1_SB_DQS_DN<8>")
	)
	(segment
		(start 61.298836 -198.591424)
		(end 61.174376 -198.715884)
		(width 0.18288)
		(layer "In4.Cu")
		(net "M_B_CPU1_SB_DQS_DN<8>")
	)
	(segment
		(start 51.33721 -199.593962)
		(end 51.064414 -199.866758)
		(width 0.18288)
		(layer "In4.Cu")
		(net "M_B_CPU1_SB_DQS_DN<8>")
	)
	(segment
		(start 87.04834 -225.203258)
		(end 87.105744 -225.145854)
		(width 0.088646)
		(layer "In4.Cu")
		(net "M_B_CPU1_SB_DQS_DN<8>")
	)
	(segment
		(start 86.735666 -225.203258)
		(end 87.04834 -225.203258)
		(width 0.088646)
		(layer "In4.Cu")
		(net "M_B_CPU1_SB_DQS_DN<8>")
	)
	(segment
		(start 51.870102 -199.805798)
		(end 51.658266 -199.593962)
		(width 0.18288)
		(layer "In4.Cu")
		(net "M_B_CPU1_SB_DQS_DN<8>")
	)
	(segment
		(start 63.872364 -199.12457)
		(end 63.747904 -199.00011)
		(width 0.18288)
		(layer "In4.Cu")
		(net "M_B_CPU1_SB_DQS_DN<8>")
	)
	(segment
		(start 86.548468 -224.878646)
		(end 86.548468 -224.8789)
		(width 0.088646)
		(layer "In4.Cu")
		(net "M_B_CPU1_SB_DQS_DN<8>")
	)
	(segment
		(start 83.115658 -222.51416)
		(end 82.791808 -222.51416)
		(width 0.088646)
		(layer "In4.Cu")
		(net "M_B_CPU1_SB_DQS_DN<8>")
	)
	(segment
		(start 80.82534 -222.574104)
		(end 76.728828 -218.477592)
		(width 0.18288)
		(layer "In4.Cu")
		(net "M_B_CPU1_SB_DQS_DN<8>")
	)
	(segment
		(start 85.608668 -224.8789)
		(end 85.607906 -224.878646)
		(width 0.088646)
		(layer "In4.Cu")
		(net "M_B_CPU1_SB_DQS_DN<8>")
	)
	(segment
		(start 59.086496 -198.94042)
		(end 55.986172 -198.94042)
		(width 0.18288)
		(layer "In4.Cu")
		(net "M_B_CPU1_SB_DQS_DN<8>")
	)
	(segment
		(start 83.798664 -223.197166)
		(end 83.115658 -222.51416)
		(width 0.088646)
		(layer "In4.Cu")
		(net "M_B_CPU1_SB_DQS_DN<8>")
	)
	(segment
		(start 82.708496 -222.574104)
		(end 80.82534 -222.574104)
		(width 0.18288)
		(layer "In4.Cu")
		(net "M_B_CPU1_SB_DQS_DN<8>")
	)
	(segment
		(start 76.728828 -218.477592)
		(end 71.228204 -205.13421)
		(width 0.18288)
		(layer "In4.Cu")
		(net "M_B_CPU1_SB_DQS_DN<8>")
	)
	(segment
		(start 60.625736 -198.715884)
		(end 60.501276 -198.591424)
		(width 0.18288)
		(layer "In4.Cu")
		(net "M_B_CPU1_SB_DQS_DN<8>")
	)
	(segment
		(start 71.228204 -205.13421)
		(end 65.094104 -199.00011)
		(width 0.18288)
		(layer "In4.Cu")
		(net "M_B_CPU1_SB_DQS_DN<8>")
	)
	(segment
		(start 84.456778 -223.976184)
		(end 84.45627 -223.975422)
		(width 0.088646)
		(layer "In4.Cu")
		(net "M_B_CPU1_SB_DQS_DN<8>")
	)
	(segment
		(start 82.731864 -222.574104)
		(end 82.708496 -222.574104)
		(width 0.088646)
		(layer "In4.Cu")
		(net "M_B_CPU1_SB_DQS_DN<8>")
	)
	(segment
		(start 84.45627 -223.975422)
		(end 83.798664 -223.317816)
		(width 0.088646)
		(layer "In4.Cu")
		(net "M_B_CPU1_SB_DQS_DN<8>")
	)
	(segment
		(start 85.043264 -224.8789)
		(end 85.042502 -224.878392)
		(width 0.088646)
		(layer "In4.Cu")
		(net "M_B_CPU1_SB_DQS_DN<8>")
	)
	(arc
		(start 85.037168 -224.875344)
		(mid 84.834581 -224.668993)
		(end 84.760562 -224.389442)
		(width 0.088646)
		(layer "In4.Cu")
		(net "M_B_CPU1_SB_DQS_DN<8>")
	)
	(arc
		(start 84.573364 -224.065338)
		(mid 84.524214 -224.033505)
		(end 84.478622 -223.996758)
		(width 0.088646)
		(layer "In4.Cu")
		(net "M_B_CPU1_SB_DQS_DN<8>")
	)
	(arc
		(start 87.099648 -225.113342)
		(mid 87.036417 -224.979614)
		(end 86.92642 -224.880678)
		(width 0.088646)
		(layer "In4.Cu")
		(net "M_B_CPU1_SB_DQS_DN<8>")
	)
	(arc
		(start 86.548468 -224.8789)
		(mid 86.265766 -224.954676)
		(end 85.983064 -224.8789)
		(width 0.088646)
		(layer "In4.Cu")
		(net "M_B_CPU1_SB_DQS_DN<8>")
	)
	(arc
		(start 86.92642 -224.880678)
		(mid 86.923112 -224.878783)
		(end 86.919816 -224.876868)
		(width 0.088646)
		(layer "In4.Cu")
		(net "M_B_CPU1_SB_DQS_DN<8>")
	)
	(arc
		(start 86.919816 -224.876868)
		(mid 86.733902 -224.828507)
		(end 86.548468 -224.878646)
		(width 0.088646)
		(layer "In4.Cu")
		(net "M_B_CPU1_SB_DQS_DN<8>")
	)
	(arc
		(start 87.105744 -225.145854)
		(mid 87.103051 -225.129531)
		(end 87.099648 -225.113342)
		(width 0.088646)
		(layer "In4.Cu")
		(net "M_B_CPU1_SB_DQS_DN<8>")
	)
	(arc
		(start 84.760562 -224.389442)
		(mid 84.710398 -224.202304)
		(end 84.573364 -224.065338)
		(width 0.088646)
		(layer "In4.Cu")
		(net "M_B_CPU1_SB_DQS_DN<8>")
	)
	(arc
		(start 84.478622 -223.996758)
		(mid 84.467562 -223.986617)
		(end 84.456778 -223.976184)
		(width 0.088646)
		(layer "In4.Cu")
		(net "M_B_CPU1_SB_DQS_DN<8>")
	)
	(arc
		(start 85.983064 -224.8789)
		(mid 85.795866 -224.828757)
		(end 85.608668 -224.8789)
		(width 0.088646)
		(layer "In4.Cu")
		(net "M_B_CPU1_SB_DQS_DN<8>")
	)
	(arc
		(start 85.607906 -224.878646)
		(mid 85.325885 -224.954202)
		(end 85.043772 -224.8789)
		(width 0.088646)
		(layer "In4.Cu")
		(net "M_B_CPU1_SB_DQS_DN<8>")
	)
	(segment
		(start 44.55033 -208.799684)
		(end 44.283884 -208.533238)
		(width 0.20066)
		(layer "F.Cu")
		(net "M_B_CPU1_SB_DQS_DN<7>")
	)
	(segment
		(start 43.148504 -208.95564)
		(end 42.887392 -209.216752)
		(width 0.20066)
		(layer "F.Cu")
		(net "M_B_CPU1_SB_DQS_DN<7>")
	)
	(segment
		(start 44.735242 -208.799684)
		(end 44.55033 -208.799684)
		(width 0.20066)
		(layer "F.Cu")
		(net "M_B_CPU1_SB_DQS_DN<7>")
	)
	(segment
		(start 49.207928 -208.95564)
		(end 48.504348 -208.95564)
		(width 0.20066)
		(layer "F.Cu")
		(net "M_B_CPU1_SB_DQS_DN<7>")
	)
	(segment
		(start 90.024712 -228.1809)
		(end 90.024966 -228.180646)
		(width 0.20066)
		(layer "F.Cu")
		(net "M_B_CPU1_SB_DQS_DN<7>")
	)
	(segment
		(start 47.46371 -208.530698)
		(end 47.202598 -208.79181)
		(width 0.20066)
		(layer "F.Cu")
		(net "M_B_CPU1_SB_DQS_DN<7>")
	)
	(segment
		(start 44.982892 -208.79181)
		(end 44.743116 -208.79181)
		(width 0.101854)
		(layer "F.Cu")
		(net "M_B_CPU1_SB_DQS_DN<7>")
	)
	(segment
		(start 48.504348 -208.95564)
		(end 47.868332 -208.530698)
		(width 0.20066)
		(layer "F.Cu")
		(net "M_B_CPU1_SB_DQS_DN<7>")
	)
	(segment
		(start 51.064414 -209.216752)
		(end 49.959514 -209.216752)
		(width 0.20066)
		(layer "F.Cu")
		(net "M_B_CPU1_SB_DQS_DN<7>")
	)
	(segment
		(start 44.283884 -208.533238)
		(end 44.044108 -208.533238)
		(width 0.20066)
		(layer "F.Cu")
		(net "M_B_CPU1_SB_DQS_DN<7>")
	)
	(segment
		(start 47.868332 -208.530698)
		(end 47.46371 -208.530698)
		(width 0.20066)
		(layer "F.Cu")
		(net "M_B_CPU1_SB_DQS_DN<7>")
	)
	(segment
		(start 42.887392 -209.216752)
		(end 42.415714 -209.216752)
		(width 0.20066)
		(layer "F.Cu")
		(net "M_B_CPU1_SB_DQS_DN<7>")
	)
	(segment
		(start 49.959514 -209.216752)
		(end 49.46904 -209.216752)
		(width 0.20066)
		(layer "F.Cu")
		(net "M_B_CPU1_SB_DQS_DN<7>")
	)
	(segment
		(start 90.024966 -228.180646)
		(end 90.024966 -227.64496)
		(width 0.20066)
		(layer "F.Cu")
		(net "M_B_CPU1_SB_DQS_DN<7>")
	)
	(segment
		(start 44.044108 -208.533238)
		(end 43.621706 -208.95564)
		(width 0.20066)
		(layer "F.Cu")
		(net "M_B_CPU1_SB_DQS_DN<7>")
	)
	(segment
		(start 43.621706 -208.95564)
		(end 43.148504 -208.95564)
		(width 0.20066)
		(layer "F.Cu")
		(net "M_B_CPU1_SB_DQS_DN<7>")
	)
	(segment
		(start 47.202598 -208.79181)
		(end 47.060358 -208.79181)
		(width 0.20066)
		(layer "F.Cu")
		(net "M_B_CPU1_SB_DQS_DN<7>")
	)
	(segment
		(start 44.743116 -208.79181)
		(end 44.735242 -208.799684)
		(width 0.101854)
		(layer "F.Cu")
		(net "M_B_CPU1_SB_DQS_DN<7>")
	)
	(segment
		(start 49.46904 -209.216752)
		(end 49.207928 -208.95564)
		(width 0.20066)
		(layer "F.Cu")
		(net "M_B_CPU1_SB_DQS_DN<7>")
	)
	(segment
		(start 47.060358 -208.79181)
		(end 44.982892 -208.79181)
		(width 0.1016)
		(layer "F.Cu")
		(net "M_B_CPU1_SB_DQS_DN<7>")
	)
	(segment
		(start 85.533738 -222.449644)
		(end 85.353906 -222.269812)
		(width 0.088646)
		(layer "In2.Cu")
		(net "M_B_CPU1_SB_DQS_DN<7>")
	)
	(segment
		(start 85.700362 -222.769176)
		(end 85.700362 -222.761556)
		(width 0.088646)
		(layer "In2.Cu")
		(net "M_B_CPU1_SB_DQS_DN<7>")
	)
	(segment
		(start 86.461854 -224.070164)
		(end 86.452964 -224.065084)
		(width 0.088646)
		(layer "In2.Cu")
		(net "M_B_CPU1_SB_DQS_DN<7>")
	)
	(segment
		(start 51.333654 -208.947512)
		(end 51.064414 -209.216752)
		(width 0.18288)
		(layer "In2.Cu")
		(net "M_B_CPU1_SB_DQS_DN<7>")
	)
	(segment
		(start 84.706206 -222.269812)
		(end 84.646262 -222.329756)
		(width 0.088646)
		(layer "In2.Cu")
		(net "M_B_CPU1_SB_DQS_DN<7>")
	)
	(segment
		(start 69.460618 -208.327752)
		(end 69.336158 -208.452212)
		(width 0.18288)
		(layer "In2.Cu")
		(net "M_B_CPU1_SB_DQS_DN<7>")
	)
	(segment
		(start 88.049862 -226.831144)
		(end 88.049862 -226.822508)
		(width 0.088646)
		(layer "In2.Cu")
		(net "M_B_CPU1_SB_DQS_DN<7>")
	)
	(segment
		(start 61.717174 -207.156558)
		(end 61.700918 -207.156558)
		(width 0.16002)
		(layer "In2.Cu")
		(net "M_B_CPU1_SB_DQS_DN<7>")
	)
	(segment
		(start 65.894966 -208.082642)
		(end 65.894966 -208.066386)
		(width 0.16002)
		(layer "In2.Cu")
		(net "M_B_CPU1_SB_DQS_DN<7>")
	)
	(segment
		(start 64.393826 -207.876902)
		(end 64.194182 -208.076546)
		(width 0.16002)
		(layer "In2.Cu")
		(net "M_B_CPU1_SB_DQS_DN<7>")
	)
	(segment
		(start 65.650872 -207.838548)
		(end 65.466214 -207.65389)
		(width 0.18288)
		(layer "In2.Cu")
		(net "M_B_CPU1_SB_DQS_DN<7>")
	)
	(segment
		(start 61.580268 -207.035908)
		(end 60.313824 -207.035908)
		(width 0.18288)
		(layer "In2.Cu")
		(net "M_B_CPU1_SB_DQS_DN<7>")
	)
	(segment
		(start 56.536082 -208.212182)
		(end 56.507888 -208.240376)
		(width 0.16002)
		(layer "In2.Cu")
		(net "M_B_CPU1_SB_DQS_DN<7>")
	)
	(segment
		(start 54.452012 -208.019904)
		(end 54.25186 -208.220056)
		(width 0.16002)
		(layer "In2.Cu")
		(net "M_B_CPU1_SB_DQS_DN<7>")
	)
	(segment
		(start 86.640416 -224.399348)
		(end 86.640416 -224.389442)
		(width 0.088646)
		(layer "In2.Cu")
		(net "M_B_CPU1_SB_DQS_DN<7>")
	)
	(segment
		(start 52.317904 -209.17281)
		(end 51.771296 -209.17281)
		(width 0.18288)
		(layer "In2.Cu")
		(net "M_B_CPU1_SB_DQS_DN<7>")
	)
	(segment
		(start 64.165988 -208.120996)
		(end 63.949834 -208.33715)
		(width 0.18288)
		(layer "In2.Cu")
		(net "M_B_CPU1_SB_DQS_DN<7>")
	)
	(segment
		(start 61.945012 -207.400652)
		(end 61.916818 -207.372458)
		(width 0.16002)
		(layer "In2.Cu")
		(net "M_B_CPU1_SB_DQS_DN<7>")
	)
	(segment
		(start 69.336158 -208.452212)
		(end 68.787518 -208.452212)
		(width 0.18288)
		(layer "In2.Cu")
		(net "M_B_CPU1_SB_DQS_DN<7>")
	)
	(segment
		(start 55.019702 -207.93329)
		(end 54.554374 -207.93329)
		(width 0.18288)
		(layer "In2.Cu")
		(net "M_B_CPU1_SB_DQS_DN<7>")
	)
	(segment
		(start 64.633094 -207.65389)
		(end 64.438276 -207.848708)
		(width 0.18288)
		(layer "In2.Cu")
		(net "M_B_CPU1_SB_DQS_DN<7>")
	)
	(segment
		(start 59.153552 -207.81518)
		(end 58.858404 -208.110328)
		(width 0.18288)
		(layer "In2.Cu")
		(net "M_B_CPU1_SB_DQS_DN<7>")
	)
	(segment
		(start 65.466214 -207.65389)
		(end 64.633094 -207.65389)
		(width 0.18288)
		(layer "In2.Cu")
		(net "M_B_CPU1_SB_DQS_DN<7>")
	)
	(segment
		(start 87.86114 -226.506024)
		(end 87.85987 -226.505262)
		(width 0.088646)
		(layer "In2.Cu")
		(net "M_B_CPU1_SB_DQS_DN<7>")
	)
	(segment
		(start 85.700362 -222.761556)
		(end 85.70087 -222.761556)
		(width 0.088646)
		(layer "In2.Cu")
		(net "M_B_CPU1_SB_DQS_DN<7>")
	)
	(segment
		(start 65.92316 -208.110836)
		(end 65.894966 -208.082642)
		(width 0.16002)
		(layer "In2.Cu")
		(net "M_B_CPU1_SB_DQS_DN<7>")
	)
	(segment
		(start 66.140076 -208.327752)
		(end 65.92316 -208.110836)
		(width 0.18288)
		(layer "In2.Cu")
		(net "M_B_CPU1_SB_DQS_DN<7>")
	)
	(segment
		(start 56.357774 -208.39049)
		(end 55.476902 -208.39049)
		(width 0.18288)
		(layer "In2.Cu")
		(net "M_B_CPU1_SB_DQS_DN<7>")
	)
	(segment
		(start 87.862664 -226.506786)
		(end 87.86114 -226.506024)
		(width 0.088646)
		(layer "In2.Cu")
		(net "M_B_CPU1_SB_DQS_DN<7>")
	)
	(segment
		(start 59.977274 -207.356202)
		(end 59.977274 -207.372458)
		(width 0.16002)
		(layer "In2.Cu")
		(net "M_B_CPU1_SB_DQS_DN<7>")
	)
	(segment
		(start 54.223666 -208.263998)
		(end 53.949854 -208.53781)
		(width 0.18288)
		(layer "In2.Cu")
		(net "M_B_CPU1_SB_DQS_DN<7>")
	)
	(segment
		(start 52.773834 -208.71688)
		(end 52.757578 -208.71688)
		(width 0.16002)
		(layer "In2.Cu")
		(net "M_B_CPU1_SB_DQS_DN<7>")
	)
	(segment
		(start 87.857076 -226.503484)
		(end 87.855044 -226.502214)
		(width 0.088646)
		(layer "In2.Cu")
		(net "M_B_CPU1_SB_DQS_DN<7>")
	)
	(segment
		(start 85.983826 -223.251776)
		(end 85.983064 -223.251268)
		(width 0.088646)
		(layer "In2.Cu")
		(net "M_B_CPU1_SB_DQS_DN<7>")
	)
	(segment
		(start 64.194182 -208.076546)
		(end 64.194182 -208.092802)
		(width 0.16002)
		(layer "In2.Cu")
		(net "M_B_CPU1_SB_DQS_DN<7>")
	)
	(segment
		(start 67.441318 -208.452212)
		(end 67.316858 -208.327752)
		(width 0.18288)
		(layer "In2.Cu")
		(net "M_B_CPU1_SB_DQS_DN<7>")
	)
	(segment
		(start 87.855044 -226.502214)
		(end 87.850472 -226.499674)
		(width 0.088646)
		(layer "In2.Cu")
		(net "M_B_CPU1_SB_DQS_DN<7>")
	)
	(segment
		(start 54.25186 -208.235804)
		(end 54.223666 -208.263998)
		(width 0.16002)
		(layer "In2.Cu")
		(net "M_B_CPU1_SB_DQS_DN<7>")
	)
	(segment
		(start 61.672724 -207.128364)
		(end 61.580268 -207.035908)
		(width 0.18288)
		(layer "In2.Cu")
		(net "M_B_CPU1_SB_DQS_DN<7>")
	)
	(segment
		(start 56.536082 -208.195926)
		(end 56.536082 -208.212182)
		(width 0.16002)
		(layer "In2.Cu")
		(net "M_B_CPU1_SB_DQS_DN<7>")
	)
	(segment
		(start 60.221368 -207.128364)
		(end 60.193174 -207.156558)
		(width 0.16002)
		(layer "In2.Cu")
		(net "M_B_CPU1_SB_DQS_DN<7>")
	)
	(segment
		(start 86.170516 -223.585532)
		(end 86.170516 -223.575626)
		(width 0.088646)
		(layer "In2.Cu")
		(net "M_B_CPU1_SB_DQS_DN<7>")
	)
	(segment
		(start 60.313824 -207.035908)
		(end 60.221368 -207.128364)
		(width 0.18288)
		(layer "In2.Cu")
		(net "M_B_CPU1_SB_DQS_DN<7>")
	)
	(segment
		(start 54.46776 -208.019904)
		(end 54.452012 -208.019904)
		(width 0.16002)
		(layer "In2.Cu")
		(net "M_B_CPU1_SB_DQS_DN<7>")
	)
	(segment
		(start 65.894966 -208.066386)
		(end 65.695322 -207.866742)
		(width 0.16002)
		(layer "In2.Cu")
		(net "M_B_CPU1_SB_DQS_DN<7>")
	)
	(segment
		(start 90.337894 -227.64496)
		(end 90.395044 -227.58781)
		(width 0.088646)
		(layer "In2.Cu")
		(net "M_B_CPU1_SB_DQS_DN<7>")
	)
	(segment
		(start 90.024966 -227.64496)
		(end 90.337894 -227.64496)
		(width 0.088646)
		(layer "In2.Cu")
		(net "M_B_CPU1_SB_DQS_DN<7>")
	)
	(segment
		(start 52.757578 -208.71688)
		(end 52.557934 -208.916524)
		(width 0.16002)
		(layer "In2.Cu")
		(net "M_B_CPU1_SB_DQS_DN<7>")
	)
	(segment
		(start 67.989958 -208.452212)
		(end 67.441318 -208.452212)
		(width 0.18288)
		(layer "In2.Cu")
		(net "M_B_CPU1_SB_DQS_DN<7>")
	)
	(segment
		(start 56.751982 -207.996282)
		(end 56.735726 -207.996282)
		(width 0.16002)
		(layer "In2.Cu")
		(net "M_B_CPU1_SB_DQS_DN<7>")
	)
	(segment
		(start 87.85987 -226.505262)
		(end 87.857076 -226.503484)
		(width 0.088646)
		(layer "In2.Cu")
		(net "M_B_CPU1_SB_DQS_DN<7>")
	)
	(segment
		(start 54.25186 -208.220056)
		(end 54.25186 -208.235804)
		(width 0.16002)
		(layer "In2.Cu")
		(net "M_B_CPU1_SB_DQS_DN<7>")
	)
	(segment
		(start 52.952904 -208.53781)
		(end 52.802028 -208.688686)
		(width 0.18288)
		(layer "In2.Cu")
		(net "M_B_CPU1_SB_DQS_DN<7>")
	)
	(segment
		(start 81.066894 -219.385388)
		(end 70.009258 -208.327752)
		(width 0.18288)
		(layer "In2.Cu")
		(net "M_B_CPU1_SB_DQS_DN<7>")
	)
	(segment
		(start 65.679066 -207.866742)
		(end 65.650872 -207.838548)
		(width 0.16002)
		(layer "In2.Cu")
		(net "M_B_CPU1_SB_DQS_DN<7>")
	)
	(segment
		(start 54.554374 -207.93329)
		(end 54.495954 -207.99171)
		(width 0.18288)
		(layer "In2.Cu")
		(net "M_B_CPU1_SB_DQS_DN<7>")
	)
	(segment
		(start 68.114418 -208.327752)
		(end 67.989958 -208.452212)
		(width 0.18288)
		(layer "In2.Cu")
		(net "M_B_CPU1_SB_DQS_DN<7>")
	)
	(segment
		(start 58.42635 -208.110328)
		(end 58.13552 -207.819498)
		(width 0.18288)
		(layer "In2.Cu")
		(net "M_B_CPU1_SB_DQS_DN<7>")
	)
	(segment
		(start 87.862664 -225.527616)
		(end 87.863426 -225.527108)
		(width 0.088646)
		(layer "In2.Cu")
		(net "M_B_CPU1_SB_DQS_DN<7>")
	)
	(segment
		(start 58.858404 -208.110328)
		(end 58.42635 -208.110328)
		(width 0.18288)
		(layer "In2.Cu")
		(net "M_B_CPU1_SB_DQS_DN<7>")
	)
	(segment
		(start 59.977274 -207.372458)
		(end 59.94908 -207.400652)
		(width 0.16002)
		(layer "In2.Cu")
		(net "M_B_CPU1_SB_DQS_DN<7>")
	)
	(segment
		(start 90.213688 -227.321364)
		(end 90.212164 -227.320602)
		(width 0.088646)
		(layer "In2.Cu")
		(net "M_B_CPU1_SB_DQS_DN<7>")
	)
	(segment
		(start 64.194182 -208.092802)
		(end 64.165988 -208.120996)
		(width 0.16002)
		(layer "In2.Cu")
		(net "M_B_CPU1_SB_DQS_DN<7>")
	)
	(segment
		(start 85.353906 -222.269812)
		(end 84.706206 -222.269812)
		(width 0.088646)
		(layer "In2.Cu")
		(net "M_B_CPU1_SB_DQS_DN<7>")
	)
	(segment
		(start 67.316858 -208.327752)
		(end 66.140076 -208.327752)
		(width 0.18288)
		(layer "In2.Cu")
		(net "M_B_CPU1_SB_DQS_DN<7>")
	)
	(segment
		(start 57.005474 -207.74279)
		(end 56.780176 -207.968088)
		(width 0.18288)
		(layer "In2.Cu")
		(net "M_B_CPU1_SB_DQS_DN<7>")
	)
	(segment
		(start 52.802028 -208.688686)
		(end 52.773834 -208.71688)
		(width 0.16002)
		(layer "In2.Cu")
		(net "M_B_CPU1_SB_DQS_DN<7>")
	)
	(segment
		(start 52.52974 -208.960974)
		(end 52.317904 -209.17281)
		(width 0.18288)
		(layer "In2.Cu")
		(net "M_B_CPU1_SB_DQS_DN<7>")
	)
	(segment
		(start 61.916818 -207.356202)
		(end 61.717174 -207.156558)
		(width 0.16002)
		(layer "In2.Cu")
		(net "M_B_CPU1_SB_DQS_DN<7>")
	)
	(segment
		(start 59.534552 -207.81518)
		(end 59.153552 -207.81518)
		(width 0.18288)
		(layer "In2.Cu")
		(net "M_B_CPU1_SB_DQS_DN<7>")
	)
	(segment
		(start 54.495954 -207.99171)
		(end 54.46776 -208.019904)
		(width 0.16002)
		(layer "In2.Cu")
		(net "M_B_CPU1_SB_DQS_DN<7>")
	)
	(segment
		(start 61.916818 -207.372458)
		(end 61.916818 -207.356202)
		(width 0.16002)
		(layer "In2.Cu")
		(net "M_B_CPU1_SB_DQS_DN<7>")
	)
	(segment
		(start 68.787518 -208.452212)
		(end 68.663058 -208.327752)
		(width 0.18288)
		(layer "In2.Cu")
		(net "M_B_CPU1_SB_DQS_DN<7>")
	)
	(segment
		(start 89.287096 -227.329238)
		(end 89.272364 -227.320602)
		(width 0.088646)
		(layer "In2.Cu")
		(net "M_B_CPU1_SB_DQS_DN<7>")
	)
	(segment
		(start 64.438276 -207.848708)
		(end 64.410082 -207.876902)
		(width 0.16002)
		(layer "In2.Cu")
		(net "M_B_CPU1_SB_DQS_DN<7>")
	)
	(segment
		(start 81.066894 -219.56141)
		(end 81.066894 -219.385388)
		(width 0.18288)
		(layer "In2.Cu")
		(net "M_B_CPU1_SB_DQS_DN<7>")
	)
	(segment
		(start 61.700918 -207.156558)
		(end 61.672724 -207.128364)
		(width 0.16002)
		(layer "In2.Cu")
		(net "M_B_CPU1_SB_DQS_DN<7>")
	)
	(segment
		(start 84.646262 -222.329756)
		(end 84.011262 -222.329756)
		(width 0.18288)
		(layer "In2.Cu")
		(net "M_B_CPU1_SB_DQS_DN<7>")
	)
	(segment
		(start 51.771296 -209.17281)
		(end 51.545998 -208.947512)
		(width 0.18288)
		(layer "In2.Cu")
		(net "M_B_CPU1_SB_DQS_DN<7>")
	)
	(segment
		(start 62.88151 -208.33715)
		(end 61.945012 -207.400652)
		(width 0.18288)
		(layer "In2.Cu")
		(net "M_B_CPU1_SB_DQS_DN<7>")
	)
	(segment
		(start 57.590182 -207.74279)
		(end 57.005474 -207.74279)
		(width 0.18288)
		(layer "In2.Cu")
		(net "M_B_CPU1_SB_DQS_DN<7>")
	)
	(segment
		(start 55.476902 -208.39049)
		(end 55.019702 -207.93329)
		(width 0.18288)
		(layer "In2.Cu")
		(net "M_B_CPU1_SB_DQS_DN<7>")
	)
	(segment
		(start 60.176918 -207.156558)
		(end 59.977274 -207.356202)
		(width 0.16002)
		(layer "In2.Cu")
		(net "M_B_CPU1_SB_DQS_DN<7>")
	)
	(segment
		(start 52.557934 -208.93278)
		(end 52.52974 -208.960974)
		(width 0.16002)
		(layer "In2.Cu")
		(net "M_B_CPU1_SB_DQS_DN<7>")
	)
	(segment
		(start 56.735726 -207.996282)
		(end 56.536082 -208.195926)
		(width 0.16002)
		(layer "In2.Cu")
		(net "M_B_CPU1_SB_DQS_DN<7>")
	)
	(segment
		(start 59.94908 -207.400652)
		(end 59.534552 -207.81518)
		(width 0.18288)
		(layer "In2.Cu")
		(net "M_B_CPU1_SB_DQS_DN<7>")
	)
	(segment
		(start 64.410082 -207.876902)
		(end 64.393826 -207.876902)
		(width 0.16002)
		(layer "In2.Cu")
		(net "M_B_CPU1_SB_DQS_DN<7>")
	)
	(segment
		(start 65.695322 -207.866742)
		(end 65.679066 -207.866742)
		(width 0.16002)
		(layer "In2.Cu")
		(net "M_B_CPU1_SB_DQS_DN<7>")
	)
	(segment
		(start 87.863426 -225.527108)
		(end 87.871554 -225.522536)
		(width 0.088646)
		(layer "In2.Cu")
		(net "M_B_CPU1_SB_DQS_DN<7>")
	)
	(segment
		(start 81.455006 -219.949522)
		(end 81.066894 -219.56141)
		(width 0.18288)
		(layer "In2.Cu")
		(net "M_B_CPU1_SB_DQS_DN<7>")
	)
	(segment
		(start 57.66689 -207.819498)
		(end 57.590182 -207.74279)
		(width 0.18288)
		(layer "In2.Cu")
		(net "M_B_CPU1_SB_DQS_DN<7>")
	)
	(segment
		(start 58.13552 -207.819498)
		(end 57.66689 -207.819498)
		(width 0.18288)
		(layer "In2.Cu")
		(net "M_B_CPU1_SB_DQS_DN<7>")
	)
	(segment
		(start 56.507888 -208.240376)
		(end 56.357774 -208.39049)
		(width 0.18288)
		(layer "In2.Cu")
		(net "M_B_CPU1_SB_DQS_DN<7>")
	)
	(segment
		(start 81.631028 -219.949522)
		(end 81.455006 -219.949522)
		(width 0.18288)
		(layer "In2.Cu")
		(net "M_B_CPU1_SB_DQS_DN<7>")
	)
	(segment
		(start 53.949854 -208.53781)
		(end 52.952904 -208.53781)
		(width 0.18288)
		(layer "In2.Cu")
		(net "M_B_CPU1_SB_DQS_DN<7>")
	)
	(segment
		(start 84.011262 -222.329756)
		(end 81.631028 -219.949522)
		(width 0.18288)
		(layer "In2.Cu")
		(net "M_B_CPU1_SB_DQS_DN<7>")
	)
	(segment
		(start 60.193174 -207.156558)
		(end 60.176918 -207.156558)
		(width 0.16002)
		(layer "In2.Cu")
		(net "M_B_CPU1_SB_DQS_DN<7>")
	)
	(segment
		(start 85.991954 -223.256348)
		(end 85.983826 -223.251776)
		(width 0.088646)
		(layer "In2.Cu")
		(net "M_B_CPU1_SB_DQS_DN<7>")
	)
	(segment
		(start 63.949834 -208.33715)
		(end 62.88151 -208.33715)
		(width 0.18288)
		(layer "In2.Cu")
		(net "M_B_CPU1_SB_DQS_DN<7>")
	)
	(segment
		(start 68.663058 -208.327752)
		(end 68.114418 -208.327752)
		(width 0.18288)
		(layer "In2.Cu")
		(net "M_B_CPU1_SB_DQS_DN<7>")
	)
	(segment
		(start 52.557934 -208.916524)
		(end 52.557934 -208.93278)
		(width 0.16002)
		(layer "In2.Cu")
		(net "M_B_CPU1_SB_DQS_DN<7>")
	)
	(segment
		(start 70.009258 -208.327752)
		(end 69.460618 -208.327752)
		(width 0.18288)
		(layer "In2.Cu")
		(net "M_B_CPU1_SB_DQS_DN<7>")
	)
	(segment
		(start 56.780176 -207.968088)
		(end 56.751982 -207.996282)
		(width 0.16002)
		(layer "In2.Cu")
		(net "M_B_CPU1_SB_DQS_DN<7>")
	)
	(segment
		(start 51.545998 -208.947512)
		(end 51.333654 -208.947512)
		(width 0.18288)
		(layer "In2.Cu")
		(net "M_B_CPU1_SB_DQS_DN<7>")
	)
	(arc
		(start 88.049862 -226.822508)
		(mid 87.997592 -226.640143)
		(end 87.862664 -226.506786)
		(width 0.088646)
		(layer "In2.Cu")
		(net "M_B_CPU1_SB_DQS_DN<7>")
	)
	(arc
		(start 87.488268 -224.8789)
		(mid 86.927292 -224.881431)
		(end 86.640416 -224.399348)
		(width 0.088646)
		(layer "In2.Cu")
		(net "M_B_CPU1_SB_DQS_DN<7>")
	)
	(arc
		(start 90.212164 -227.320602)
		(mid 90.024966 -227.270459)
		(end 89.837768 -227.320602)
		(width 0.088646)
		(layer "In2.Cu")
		(net "M_B_CPU1_SB_DQS_DN<7>")
	)
	(arc
		(start 85.983064 -223.251268)
		(mid 85.777992 -223.047589)
		(end 85.700362 -222.769176)
		(width 0.088646)
		(layer "In2.Cu")
		(net "M_B_CPU1_SB_DQS_DN<7>")
	)
	(arc
		(start 89.272364 -227.320602)
		(mid 89.085166 -227.270459)
		(end 88.897968 -227.320602)
		(width 0.088646)
		(layer "In2.Cu")
		(net "M_B_CPU1_SB_DQS_DN<7>")
	)
	(arc
		(start 90.395044 -227.58781)
		(mid 90.33447 -227.4341)
		(end 90.213688 -227.321364)
		(width 0.088646)
		(layer "In2.Cu")
		(net "M_B_CPU1_SB_DQS_DN<7>")
	)
	(arc
		(start 86.170516 -223.575626)
		(mid 86.122837 -223.392726)
		(end 85.991954 -223.256348)
		(width 0.088646)
		(layer "In2.Cu")
		(net "M_B_CPU1_SB_DQS_DN<7>")
	)
	(arc
		(start 87.871554 -225.522536)
		(mid 87.997394 -225.011551)
		(end 87.488268 -224.8789)
		(width 0.088646)
		(layer "In2.Cu")
		(net "M_B_CPU1_SB_DQS_DN<7>")
	)
	(arc
		(start 85.70087 -222.761556)
		(mid 85.656456 -222.584619)
		(end 85.533738 -222.449644)
		(width 0.088646)
		(layer "In2.Cu")
		(net "M_B_CPU1_SB_DQS_DN<7>")
	)
	(arc
		(start 88.897968 -227.320602)
		(mid 88.332469 -227.320841)
		(end 88.049862 -226.831144)
		(width 0.088646)
		(layer "In2.Cu")
		(net "M_B_CPU1_SB_DQS_DN<7>")
	)
	(arc
		(start 86.452964 -224.065084)
		(mid 86.248629 -223.862479)
		(end 86.170516 -223.585532)
		(width 0.088646)
		(layer "In2.Cu")
		(net "M_B_CPU1_SB_DQS_DN<7>")
	)
	(arc
		(start 87.850472 -226.499674)
		(mid 87.57994 -226.010207)
		(end 87.862664 -225.527616)
		(width 0.088646)
		(layer "In2.Cu")
		(net "M_B_CPU1_SB_DQS_DN<7>")
	)
	(arc
		(start 89.837768 -227.320602)
		(mid 89.563569 -227.396437)
		(end 89.287096 -227.329238)
		(width 0.088646)
		(layer "In2.Cu")
		(net "M_B_CPU1_SB_DQS_DN<7>")
	)
	(arc
		(start 86.640416 -224.389442)
		(mid 86.592737 -224.206542)
		(end 86.461854 -224.070164)
		(width 0.088646)
		(layer "In2.Cu")
		(net "M_B_CPU1_SB_DQS_DN<7>")
	)
	(segment
		(start 47.202598 -218.141804)
		(end 47.060358 -218.141804)
		(width 0.20066)
		(layer "F.Cu")
		(net "M_B_CPU1_SB_DQS_DN<6>")
	)
	(segment
		(start 47.46371 -217.880692)
		(end 47.202598 -218.141804)
		(width 0.20066)
		(layer "F.Cu")
		(net "M_B_CPU1_SB_DQS_DN<6>")
	)
	(segment
		(start 48.504348 -218.305634)
		(end 47.868332 -217.880692)
		(width 0.20066)
		(layer "F.Cu")
		(net "M_B_CPU1_SB_DQS_DN<6>")
	)
	(segment
		(start 90.024966 -233.06405)
		(end 90.024966 -232.528364)
		(width 0.20066)
		(layer "F.Cu")
		(net "M_B_CPU1_SB_DQS_DN<6>")
	)
	(segment
		(start 49.207928 -218.305634)
		(end 48.504348 -218.305634)
		(width 0.20066)
		(layer "F.Cu")
		(net "M_B_CPU1_SB_DQS_DN<6>")
	)
	(segment
		(start 42.887392 -218.566746)
		(end 42.415714 -218.566746)
		(width 0.20066)
		(layer "F.Cu")
		(net "M_B_CPU1_SB_DQS_DN<6>")
	)
	(segment
		(start 90.024712 -233.064304)
		(end 90.024966 -233.06405)
		(width 0.20066)
		(layer "F.Cu")
		(net "M_B_CPU1_SB_DQS_DN<6>")
	)
	(segment
		(start 47.060358 -218.141804)
		(end 44.982892 -218.141804)
		(width 0.1016)
		(layer "F.Cu")
		(net "M_B_CPU1_SB_DQS_DN<6>")
	)
	(segment
		(start 43.148504 -218.305634)
		(end 42.887392 -218.566746)
		(width 0.20066)
		(layer "F.Cu")
		(net "M_B_CPU1_SB_DQS_DN<6>")
	)
	(segment
		(start 44.735242 -218.149678)
		(end 44.55033 -218.149678)
		(width 0.20066)
		(layer "F.Cu")
		(net "M_B_CPU1_SB_DQS_DN<6>")
	)
	(segment
		(start 44.982892 -218.141804)
		(end 44.743116 -218.141804)
		(width 0.101854)
		(layer "F.Cu")
		(net "M_B_CPU1_SB_DQS_DN<6>")
	)
	(segment
		(start 49.46904 -218.566746)
		(end 49.207928 -218.305634)
		(width 0.20066)
		(layer "F.Cu")
		(net "M_B_CPU1_SB_DQS_DN<6>")
	)
	(segment
		(start 51.064414 -218.566746)
		(end 49.959514 -218.566746)
		(width 0.20066)
		(layer "F.Cu")
		(net "M_B_CPU1_SB_DQS_DN<6>")
	)
	(segment
		(start 44.743116 -218.141804)
		(end 44.735242 -218.149678)
		(width 0.101854)
		(layer "F.Cu")
		(net "M_B_CPU1_SB_DQS_DN<6>")
	)
	(segment
		(start 47.868332 -217.880692)
		(end 47.46371 -217.880692)
		(width 0.20066)
		(layer "F.Cu")
		(net "M_B_CPU1_SB_DQS_DN<6>")
	)
	(segment
		(start 43.621706 -218.305634)
		(end 43.148504 -218.305634)
		(width 0.20066)
		(layer "F.Cu")
		(net "M_B_CPU1_SB_DQS_DN<6>")
	)
	(segment
		(start 44.55033 -218.149678)
		(end 44.283884 -217.883232)
		(width 0.20066)
		(layer "F.Cu")
		(net "M_B_CPU1_SB_DQS_DN<6>")
	)
	(segment
		(start 49.959514 -218.566746)
		(end 49.46904 -218.566746)
		(width 0.20066)
		(layer "F.Cu")
		(net "M_B_CPU1_SB_DQS_DN<6>")
	)
	(segment
		(start 44.283884 -217.883232)
		(end 44.044108 -217.883232)
		(width 0.20066)
		(layer "F.Cu")
		(net "M_B_CPU1_SB_DQS_DN<6>")
	)
	(segment
		(start 44.044108 -217.883232)
		(end 43.621706 -218.305634)
		(width 0.20066)
		(layer "F.Cu")
		(net "M_B_CPU1_SB_DQS_DN<6>")
	)
	(segment
		(start 54.041294 -218.09075)
		(end 52.749958 -218.09075)
		(width 0.18288)
		(layer "In2.Cu")
		(net "M_B_CPU1_SB_DQS_DN<6>")
	)
	(segment
		(start 59.977274 -218.406218)
		(end 59.977274 -218.422474)
		(width 0.16002)
		(layer "In2.Cu")
		(net "M_B_CPU1_SB_DQS_DN<6>")
	)
	(segment
		(start 66.991738 -217.739468)
		(end 66.184018 -217.739468)
		(width 0.18288)
		(layer "In2.Cu")
		(net "M_B_CPU1_SB_DQS_DN<6>")
	)
	(segment
		(start 89.287096 -232.212642)
		(end 89.272364 -232.204006)
		(width 0.088646)
		(layer "In2.Cu")
		(net "M_B_CPU1_SB_DQS_DN<6>")
	)
	(segment
		(start 61.699394 -218.178634)
		(end 61.683138 -218.178634)
		(width 0.16002)
		(layer "In2.Cu")
		(net "M_B_CPU1_SB_DQS_DN<6>")
	)
	(segment
		(start 61.683138 -218.178634)
		(end 61.654944 -218.15044)
		(width 0.16002)
		(layer "In2.Cu")
		(net "M_B_CPU1_SB_DQS_DN<6>")
	)
	(segment
		(start 56.763666 -219.379546)
		(end 56.558434 -219.174314)
		(width 0.18288)
		(layer "In2.Cu")
		(net "M_B_CPU1_SB_DQS_DN<6>")
	)
	(segment
		(start 56.330088 -218.93022)
		(end 56.31434 -218.93022)
		(width 0.16002)
		(layer "In2.Cu")
		(net "M_B_CPU1_SB_DQS_DN<6>")
	)
	(segment
		(start 77.234796 -225.466148)
		(end 77.234796 -225.290126)
		(width 0.18288)
		(layer "In2.Cu")
		(net "M_B_CPU1_SB_DQS_DN<6>")
	)
	(segment
		(start 64.077342 -217.55608)
		(end 64.077342 -217.572336)
		(width 0.16002)
		(layer "In2.Cu")
		(net "M_B_CPU1_SB_DQS_DN<6>")
	)
	(segment
		(start 76.846938 -224.902268)
		(end 76.670916 -224.902268)
		(width 0.18288)
		(layer "In2.Cu")
		(net "M_B_CPU1_SB_DQS_DN<6>")
	)
	(segment
		(start 85.138514 -232.204006)
		(end 85.123782 -232.212642)
		(width 0.088646)
		(layer "In2.Cu")
		(net "M_B_CPU1_SB_DQS_DN<6>")
	)
	(segment
		(start 76.670916 -224.902268)
		(end 76.282804 -224.514156)
		(width 0.18288)
		(layer "In2.Cu")
		(net "M_B_CPU1_SB_DQS_DN<6>")
	)
	(segment
		(start 54.128924 -218.17838)
		(end 54.041294 -218.09075)
		(width 0.18288)
		(layer "In2.Cu")
		(net "M_B_CPU1_SB_DQS_DN<6>")
	)
	(segment
		(start 52.456334 -218.368118)
		(end 52.456334 -218.384374)
		(width 0.16002)
		(layer "In2.Cu")
		(net "M_B_CPU1_SB_DQS_DN<6>")
	)
	(segment
		(start 68.337938 -217.739468)
		(end 67.789298 -217.739468)
		(width 0.18288)
		(layer "In2.Cu")
		(net "M_B_CPU1_SB_DQS_DN<6>")
	)
	(segment
		(start 83.998816 -232.153206)
		(end 83.70951 -231.863392)
		(width 0.088646)
		(layer "In2.Cu")
		(net "M_B_CPU1_SB_DQS_DN<6>")
	)
	(segment
		(start 52.700428 -218.14028)
		(end 52.672234 -218.168474)
		(width 0.16002)
		(layer "In2.Cu")
		(net "M_B_CPU1_SB_DQS_DN<6>")
	)
	(segment
		(start 61.654944 -218.15044)
		(end 61.60897 -218.104466)
		(width 0.18288)
		(layer "In2.Cu")
		(net "M_B_CPU1_SB_DQS_DN<6>")
	)
	(segment
		(start 64.39535 -217.254328)
		(end 64.321436 -217.328242)
		(width 0.18288)
		(layer "In2.Cu")
		(net "M_B_CPU1_SB_DQS_DN<6>")
	)
	(segment
		(start 77.622908 -225.85426)
		(end 77.234796 -225.466148)
		(width 0.18288)
		(layer "In2.Cu")
		(net "M_B_CPU1_SB_DQS_DN<6>")
	)
	(segment
		(start 61.899038 -218.394534)
		(end 61.899038 -218.378278)
		(width 0.16002)
		(layer "In2.Cu")
		(net "M_B_CPU1_SB_DQS_DN<6>")
	)
	(segment
		(start 67.116198 -217.863928)
		(end 66.991738 -217.739468)
		(width 0.18288)
		(layer "In2.Cu")
		(net "M_B_CPU1_SB_DQS_DN<6>")
	)
	(segment
		(start 83.70951 -231.863392)
		(end 83.624674 -231.863392)
		(width 0.088646)
		(layer "In2.Cu")
		(net "M_B_CPU1_SB_DQS_DN<6>")
	)
	(segment
		(start 90.024966 -232.528364)
		(end 90.33764 -232.528364)
		(width 0.088646)
		(layer "In2.Cu")
		(net "M_B_CPU1_SB_DQS_DN<6>")
	)
	(segment
		(start 69.135498 -217.739468)
		(end 69.011038 -217.863928)
		(width 0.18288)
		(layer "In2.Cu")
		(net "M_B_CPU1_SB_DQS_DN<6>")
	)
	(segment
		(start 52.42814 -218.412568)
		(end 52.267358 -218.57335)
		(width 0.18288)
		(layer "In2.Cu")
		(net "M_B_CPU1_SB_DQS_DN<6>")
	)
	(segment
		(start 78.186788 -226.425506)
		(end 78.186788 -226.242118)
		(width 0.18288)
		(layer "In2.Cu")
		(net "M_B_CPU1_SB_DQS_DN<6>")
	)
	(segment
		(start 56.558434 -219.174314)
		(end 56.53024 -219.14612)
		(width 0.16002)
		(layer "In2.Cu")
		(net "M_B_CPU1_SB_DQS_DN<6>")
	)
	(segment
		(start 68.462398 -217.863928)
		(end 68.337938 -217.739468)
		(width 0.18288)
		(layer "In2.Cu")
		(net "M_B_CPU1_SB_DQS_DN<6>")
	)
	(segment
		(start 56.53024 -219.14612)
		(end 56.53024 -219.130372)
		(width 0.16002)
		(layer "In2.Cu")
		(net "M_B_CPU1_SB_DQS_DN<6>")
	)
	(segment
		(start 63.747142 -217.902536)
		(end 63.291466 -217.902536)
		(width 0.18288)
		(layer "In2.Cu")
		(net "M_B_CPU1_SB_DQS_DN<6>")
	)
	(segment
		(start 61.899038 -218.378278)
		(end 61.699394 -218.178634)
		(width 0.16002)
		(layer "In2.Cu")
		(net "M_B_CPU1_SB_DQS_DN<6>")
	)
	(segment
		(start 60.295282 -218.104466)
		(end 60.221368 -218.17838)
		(width 0.18288)
		(layer "In2.Cu")
		(net "M_B_CPU1_SB_DQS_DN<6>")
	)
	(segment
		(start 60.221368 -218.17838)
		(end 60.193174 -218.206574)
		(width 0.16002)
		(layer "In2.Cu")
		(net "M_B_CPU1_SB_DQS_DN<6>")
	)
	(segment
		(start 52.749958 -218.09075)
		(end 52.700428 -218.14028)
		(width 0.18288)
		(layer "In2.Cu")
		(net "M_B_CPU1_SB_DQS_DN<6>")
	)
	(segment
		(start 69.684138 -217.739468)
		(end 69.135498 -217.739468)
		(width 0.18288)
		(layer "In2.Cu")
		(net "M_B_CPU1_SB_DQS_DN<6>")
	)
	(segment
		(start 51.534568 -218.290902)
		(end 51.340258 -218.290902)
		(width 0.18288)
		(layer "In2.Cu")
		(net "M_B_CPU1_SB_DQS_DN<6>")
	)
	(segment
		(start 58.67654 -218.93022)
		(end 58.476388 -219.130372)
		(width 0.16002)
		(layer "In2.Cu")
		(net "M_B_CPU1_SB_DQS_DN<6>")
	)
	(segment
		(start 86.078568 -232.204006)
		(end 86.068154 -232.210102)
		(width 0.088646)
		(layer "In2.Cu")
		(net "M_B_CPU1_SB_DQS_DN<6>")
	)
	(segment
		(start 64.049148 -217.60053)
		(end 63.747142 -217.902536)
		(width 0.18288)
		(layer "In2.Cu")
		(net "M_B_CPU1_SB_DQS_DN<6>")
	)
	(segment
		(start 56.31434 -218.93022)
		(end 56.286146 -218.902026)
		(width 0.16002)
		(layer "In2.Cu")
		(net "M_B_CPU1_SB_DQS_DN<6>")
	)
	(segment
		(start 54.373018 -218.406218)
		(end 54.173374 -218.206574)
		(width 0.16002)
		(layer "In2.Cu")
		(net "M_B_CPU1_SB_DQS_DN<6>")
	)
	(segment
		(start 76.282804 -224.514156)
		(end 76.282804 -224.338134)
		(width 0.18288)
		(layer "In2.Cu")
		(net "M_B_CPU1_SB_DQS_DN<6>")
	)
	(segment
		(start 64.276986 -217.356436)
		(end 64.077342 -217.55608)
		(width 0.16002)
		(layer "In2.Cu")
		(net "M_B_CPU1_SB_DQS_DN<6>")
	)
	(segment
		(start 60.176918 -218.206574)
		(end 59.977274 -218.406218)
		(width 0.16002)
		(layer "In2.Cu")
		(net "M_B_CPU1_SB_DQS_DN<6>")
	)
	(segment
		(start 54.373018 -218.422474)
		(end 54.373018 -218.406218)
		(width 0.16002)
		(layer "In2.Cu")
		(net "M_B_CPU1_SB_DQS_DN<6>")
	)
	(segment
		(start 59.977274 -218.422474)
		(end 59.94908 -218.450668)
		(width 0.16002)
		(layer "In2.Cu")
		(net "M_B_CPU1_SB_DQS_DN<6>")
	)
	(segment
		(start 65.698878 -217.254328)
		(end 64.39535 -217.254328)
		(width 0.18288)
		(layer "In2.Cu")
		(net "M_B_CPU1_SB_DQS_DN<6>")
	)
	(segment
		(start 58.720482 -218.902026)
		(end 58.692288 -218.93022)
		(width 0.16002)
		(layer "In2.Cu")
		(net "M_B_CPU1_SB_DQS_DN<6>")
	)
	(segment
		(start 67.789298 -217.739468)
		(end 67.664838 -217.863928)
		(width 0.18288)
		(layer "In2.Cu")
		(net "M_B_CPU1_SB_DQS_DN<6>")
	)
	(segment
		(start 76.282804 -224.338134)
		(end 69.684138 -217.739468)
		(width 0.18288)
		(layer "In2.Cu")
		(net "M_B_CPU1_SB_DQS_DN<6>")
	)
	(segment
		(start 65.772792 -217.328242)
		(end 65.698878 -217.254328)
		(width 0.18288)
		(layer "In2.Cu")
		(net "M_B_CPU1_SB_DQS_DN<6>")
	)
	(segment
		(start 66.016886 -217.572336)
		(end 66.016886 -217.55608)
		(width 0.16002)
		(layer "In2.Cu")
		(net "M_B_CPU1_SB_DQS_DN<6>")
	)
	(segment
		(start 52.655978 -218.168474)
		(end 52.456334 -218.368118)
		(width 0.16002)
		(layer "In2.Cu")
		(net "M_B_CPU1_SB_DQS_DN<6>")
	)
	(segment
		(start 58.242962 -219.379546)
		(end 56.763666 -219.379546)
		(width 0.18288)
		(layer "In2.Cu")
		(net "M_B_CPU1_SB_DQS_DN<6>")
	)
	(segment
		(start 52.672234 -218.168474)
		(end 52.655978 -218.168474)
		(width 0.16002)
		(layer "In2.Cu")
		(net "M_B_CPU1_SB_DQS_DN<6>")
	)
	(segment
		(start 83.624674 -231.863392)
		(end 78.186788 -226.425506)
		(width 0.18288)
		(layer "In2.Cu")
		(net "M_B_CPU1_SB_DQS_DN<6>")
	)
	(segment
		(start 58.917078 -218.70543)
		(end 58.720482 -218.902026)
		(width 0.18288)
		(layer "In2.Cu")
		(net "M_B_CPU1_SB_DQS_DN<6>")
	)
	(segment
		(start 67.664838 -217.863928)
		(end 67.116198 -217.863928)
		(width 0.18288)
		(layer "In2.Cu")
		(net "M_B_CPU1_SB_DQS_DN<6>")
	)
	(segment
		(start 63.291466 -217.902536)
		(end 62.616334 -218.577668)
		(width 0.18288)
		(layer "In2.Cu")
		(net "M_B_CPU1_SB_DQS_DN<6>")
	)
	(segment
		(start 77.234796 -225.290126)
		(end 76.846938 -224.902268)
		(width 0.18288)
		(layer "In2.Cu")
		(net "M_B_CPU1_SB_DQS_DN<6>")
	)
	(segment
		(start 51.340258 -218.290902)
		(end 51.064414 -218.566746)
		(width 0.18288)
		(layer "In2.Cu")
		(net "M_B_CPU1_SB_DQS_DN<6>")
	)
	(segment
		(start 54.173374 -218.206574)
		(end 54.157118 -218.206574)
		(width 0.16002)
		(layer "In2.Cu")
		(net "M_B_CPU1_SB_DQS_DN<6>")
	)
	(segment
		(start 90.33764 -232.528364)
		(end 90.395044 -232.47096)
		(width 0.088646)
		(layer "In2.Cu")
		(net "M_B_CPU1_SB_DQS_DN<6>")
	)
	(segment
		(start 52.456334 -218.384374)
		(end 52.42814 -218.412568)
		(width 0.16002)
		(layer "In2.Cu")
		(net "M_B_CPU1_SB_DQS_DN<6>")
	)
	(segment
		(start 66.016886 -217.55608)
		(end 65.817242 -217.356436)
		(width 0.16002)
		(layer "In2.Cu")
		(net "M_B_CPU1_SB_DQS_DN<6>")
	)
	(segment
		(start 54.401212 -218.450668)
		(end 54.373018 -218.422474)
		(width 0.16002)
		(layer "In2.Cu")
		(net "M_B_CPU1_SB_DQS_DN<6>")
	)
	(segment
		(start 58.476388 -219.14612)
		(end 58.448194 -219.174314)
		(width 0.16002)
		(layer "In2.Cu")
		(net "M_B_CPU1_SB_DQS_DN<6>")
	)
	(segment
		(start 54.605174 -218.65463)
		(end 54.401212 -218.450668)
		(width 0.18288)
		(layer "In2.Cu")
		(net "M_B_CPU1_SB_DQS_DN<6>")
	)
	(segment
		(start 65.800986 -217.356436)
		(end 65.772792 -217.328242)
		(width 0.16002)
		(layer "In2.Cu")
		(net "M_B_CPU1_SB_DQS_DN<6>")
	)
	(segment
		(start 58.448194 -219.174314)
		(end 58.242962 -219.379546)
		(width 0.18288)
		(layer "In2.Cu")
		(net "M_B_CPU1_SB_DQS_DN<6>")
	)
	(segment
		(start 66.184018 -217.739468)
		(end 66.04508 -217.60053)
		(width 0.18288)
		(layer "In2.Cu")
		(net "M_B_CPU1_SB_DQS_DN<6>")
	)
	(segment
		(start 61.60897 -218.104466)
		(end 60.295282 -218.104466)
		(width 0.18288)
		(layer "In2.Cu")
		(net "M_B_CPU1_SB_DQS_DN<6>")
	)
	(segment
		(start 58.476388 -219.130372)
		(end 58.476388 -219.14612)
		(width 0.16002)
		(layer "In2.Cu")
		(net "M_B_CPU1_SB_DQS_DN<6>")
	)
	(segment
		(start 77.79893 -225.85426)
		(end 77.622908 -225.85426)
		(width 0.18288)
		(layer "In2.Cu")
		(net "M_B_CPU1_SB_DQS_DN<6>")
	)
	(segment
		(start 52.267358 -218.57335)
		(end 51.817016 -218.57335)
		(width 0.18288)
		(layer "In2.Cu")
		(net "M_B_CPU1_SB_DQS_DN<6>")
	)
	(segment
		(start 59.694318 -218.70543)
		(end 58.917078 -218.70543)
		(width 0.18288)
		(layer "In2.Cu")
		(net "M_B_CPU1_SB_DQS_DN<6>")
	)
	(segment
		(start 56.286146 -218.902026)
		(end 56.03875 -218.65463)
		(width 0.18288)
		(layer "In2.Cu")
		(net "M_B_CPU1_SB_DQS_DN<6>")
	)
	(segment
		(start 56.03875 -218.65463)
		(end 54.605174 -218.65463)
		(width 0.18288)
		(layer "In2.Cu")
		(net "M_B_CPU1_SB_DQS_DN<6>")
	)
	(segment
		(start 64.077342 -217.572336)
		(end 64.049148 -217.60053)
		(width 0.16002)
		(layer "In2.Cu")
		(net "M_B_CPU1_SB_DQS_DN<6>")
	)
	(segment
		(start 64.293242 -217.356436)
		(end 64.276986 -217.356436)
		(width 0.16002)
		(layer "In2.Cu")
		(net "M_B_CPU1_SB_DQS_DN<6>")
	)
	(segment
		(start 66.04508 -217.60053)
		(end 66.016886 -217.572336)
		(width 0.16002)
		(layer "In2.Cu")
		(net "M_B_CPU1_SB_DQS_DN<6>")
	)
	(segment
		(start 59.94908 -218.450668)
		(end 59.694318 -218.70543)
		(width 0.18288)
		(layer "In2.Cu")
		(net "M_B_CPU1_SB_DQS_DN<6>")
	)
	(segment
		(start 58.692288 -218.93022)
		(end 58.67654 -218.93022)
		(width 0.16002)
		(layer "In2.Cu")
		(net "M_B_CPU1_SB_DQS_DN<6>")
	)
	(segment
		(start 65.817242 -217.356436)
		(end 65.800986 -217.356436)
		(width 0.16002)
		(layer "In2.Cu")
		(net "M_B_CPU1_SB_DQS_DN<6>")
	)
	(segment
		(start 54.157118 -218.206574)
		(end 54.128924 -218.17838)
		(width 0.16002)
		(layer "In2.Cu")
		(net "M_B_CPU1_SB_DQS_DN<6>")
	)
	(segment
		(start 56.53024 -219.130372)
		(end 56.330088 -218.93022)
		(width 0.16002)
		(layer "In2.Cu")
		(net "M_B_CPU1_SB_DQS_DN<6>")
	)
	(segment
		(start 69.011038 -217.863928)
		(end 68.462398 -217.863928)
		(width 0.18288)
		(layer "In2.Cu")
		(net "M_B_CPU1_SB_DQS_DN<6>")
	)
	(segment
		(start 62.082172 -218.577668)
		(end 61.927232 -218.422728)
		(width 0.18288)
		(layer "In2.Cu")
		(net "M_B_CPU1_SB_DQS_DN<6>")
	)
	(segment
		(start 60.193174 -218.206574)
		(end 60.176918 -218.206574)
		(width 0.16002)
		(layer "In2.Cu")
		(net "M_B_CPU1_SB_DQS_DN<6>")
	)
	(segment
		(start 64.321436 -217.328242)
		(end 64.293242 -217.356436)
		(width 0.16002)
		(layer "In2.Cu")
		(net "M_B_CPU1_SB_DQS_DN<6>")
	)
	(segment
		(start 84.385912 -232.153206)
		(end 83.998816 -232.153206)
		(width 0.088646)
		(layer "In2.Cu")
		(net "M_B_CPU1_SB_DQS_DN<6>")
	)
	(segment
		(start 88.347296 -232.212642)
		(end 88.332564 -232.204006)
		(width 0.088646)
		(layer "In2.Cu")
		(net "M_B_CPU1_SB_DQS_DN<6>")
	)
	(segment
		(start 78.186788 -226.242118)
		(end 77.79893 -225.85426)
		(width 0.18288)
		(layer "In2.Cu")
		(net "M_B_CPU1_SB_DQS_DN<6>")
	)
	(segment
		(start 62.616334 -218.577668)
		(end 62.082172 -218.577668)
		(width 0.18288)
		(layer "In2.Cu")
		(net "M_B_CPU1_SB_DQS_DN<6>")
	)
	(segment
		(start 51.817016 -218.57335)
		(end 51.534568 -218.290902)
		(width 0.18288)
		(layer "In2.Cu")
		(net "M_B_CPU1_SB_DQS_DN<6>")
	)
	(segment
		(start 61.927232 -218.422728)
		(end 61.899038 -218.394534)
		(width 0.16002)
		(layer "In2.Cu")
		(net "M_B_CPU1_SB_DQS_DN<6>")
	)
	(arc
		(start 89.837768 -232.204006)
		(mid 89.563569 -232.279841)
		(end 89.287096 -232.212642)
		(width 0.088646)
		(layer "In2.Cu")
		(net "M_B_CPU1_SB_DQS_DN<6>")
	)
	(arc
		(start 89.272364 -232.204006)
		(mid 89.085166 -232.153863)
		(end 88.897968 -232.204006)
		(width 0.088646)
		(layer "In2.Cu")
		(net "M_B_CPU1_SB_DQS_DN<6>")
	)
	(arc
		(start 85.123782 -232.212642)
		(mid 84.847307 -232.279962)
		(end 84.57311 -232.204006)
		(width 0.088646)
		(layer "In2.Cu")
		(net "M_B_CPU1_SB_DQS_DN<6>")
	)
	(arc
		(start 87.392764 -232.204006)
		(mid 87.205566 -232.153863)
		(end 87.018368 -232.204006)
		(width 0.088646)
		(layer "In2.Cu")
		(net "M_B_CPU1_SB_DQS_DN<6>")
	)
	(arc
		(start 87.958168 -232.204006)
		(mid 87.675466 -232.279782)
		(end 87.392764 -232.204006)
		(width 0.088646)
		(layer "In2.Cu")
		(net "M_B_CPU1_SB_DQS_DN<6>")
	)
	(arc
		(start 85.51291 -232.204006)
		(mid 85.325712 -232.153863)
		(end 85.138514 -232.204006)
		(width 0.088646)
		(layer "In2.Cu")
		(net "M_B_CPU1_SB_DQS_DN<6>")
	)
	(arc
		(start 86.068154 -232.210102)
		(mid 85.789722 -232.279948)
		(end 85.51291 -232.204006)
		(width 0.088646)
		(layer "In2.Cu")
		(net "M_B_CPU1_SB_DQS_DN<6>")
	)
	(arc
		(start 88.897968 -232.204006)
		(mid 88.623769 -232.279841)
		(end 88.347296 -232.212642)
		(width 0.088646)
		(layer "In2.Cu")
		(net "M_B_CPU1_SB_DQS_DN<6>")
	)
	(arc
		(start 87.018368 -232.204006)
		(mid 86.735666 -232.279782)
		(end 86.452964 -232.204006)
		(width 0.088646)
		(layer "In2.Cu")
		(net "M_B_CPU1_SB_DQS_DN<6>")
	)
	(arc
		(start 86.452964 -232.204006)
		(mid 86.265766 -232.153863)
		(end 86.078568 -232.204006)
		(width 0.088646)
		(layer "In2.Cu")
		(net "M_B_CPU1_SB_DQS_DN<6>")
	)
	(arc
		(start 84.57311 -232.204006)
		(mid 84.482854 -232.166284)
		(end 84.385912 -232.153206)
		(width 0.088646)
		(layer "In2.Cu")
		(net "M_B_CPU1_SB_DQS_DN<6>")
	)
	(arc
		(start 88.332564 -232.204006)
		(mid 88.145366 -232.153863)
		(end 87.958168 -232.204006)
		(width 0.088646)
		(layer "In2.Cu")
		(net "M_B_CPU1_SB_DQS_DN<6>")
	)
	(arc
		(start 90.395044 -232.47096)
		(mid 90.186761 -232.190614)
		(end 89.837768 -232.204006)
		(width 0.088646)
		(layer "In2.Cu")
		(net "M_B_CPU1_SB_DQS_DN<6>")
	)
	(segment
		(start 42.887392 -227.91674)
		(end 42.415714 -227.91674)
		(width 0.20066)
		(layer "F.Cu")
		(net "M_B_CPU1_SB_DQS_DN<5>")
	)
	(segment
		(start 47.868332 -227.230686)
		(end 47.46371 -227.230686)
		(width 0.20066)
		(layer "F.Cu")
		(net "M_B_CPU1_SB_DQS_DN<5>")
	)
	(segment
		(start 44.55033 -227.499672)
		(end 44.283884 -227.233226)
		(width 0.20066)
		(layer "F.Cu")
		(net "M_B_CPU1_SB_DQS_DN<5>")
	)
	(segment
		(start 93.314012 -235.505752)
		(end 93.314012 -234.970066)
		(width 0.20066)
		(layer "F.Cu")
		(net "M_B_CPU1_SB_DQS_DN<5>")
	)
	(segment
		(start 51.064414 -227.91674)
		(end 49.959514 -227.91674)
		(width 0.20066)
		(layer "F.Cu")
		(net "M_B_CPU1_SB_DQS_DN<5>")
	)
	(segment
		(start 49.46904 -227.91674)
		(end 49.207928 -227.655628)
		(width 0.20066)
		(layer "F.Cu")
		(net "M_B_CPU1_SB_DQS_DN<5>")
	)
	(segment
		(start 44.283884 -227.233226)
		(end 44.044108 -227.233226)
		(width 0.20066)
		(layer "F.Cu")
		(net "M_B_CPU1_SB_DQS_DN<5>")
	)
	(segment
		(start 48.504348 -227.655628)
		(end 47.868332 -227.230686)
		(width 0.20066)
		(layer "F.Cu")
		(net "M_B_CPU1_SB_DQS_DN<5>")
	)
	(segment
		(start 44.735242 -227.499672)
		(end 44.55033 -227.499672)
		(width 0.20066)
		(layer "F.Cu")
		(net "M_B_CPU1_SB_DQS_DN<5>")
	)
	(segment
		(start 44.743116 -227.491798)
		(end 44.735242 -227.499672)
		(width 0.101854)
		(layer "F.Cu")
		(net "M_B_CPU1_SB_DQS_DN<5>")
	)
	(segment
		(start 49.207928 -227.655628)
		(end 48.504348 -227.655628)
		(width 0.20066)
		(layer "F.Cu")
		(net "M_B_CPU1_SB_DQS_DN<5>")
	)
	(segment
		(start 43.148504 -227.655628)
		(end 42.887392 -227.91674)
		(width 0.20066)
		(layer "F.Cu")
		(net "M_B_CPU1_SB_DQS_DN<5>")
	)
	(segment
		(start 47.202598 -227.491798)
		(end 47.060358 -227.491798)
		(width 0.20066)
		(layer "F.Cu")
		(net "M_B_CPU1_SB_DQS_DN<5>")
	)
	(segment
		(start 44.044108 -227.233226)
		(end 43.621706 -227.655628)
		(width 0.20066)
		(layer "F.Cu")
		(net "M_B_CPU1_SB_DQS_DN<5>")
	)
	(segment
		(start 44.982892 -227.491798)
		(end 44.743116 -227.491798)
		(width 0.101854)
		(layer "F.Cu")
		(net "M_B_CPU1_SB_DQS_DN<5>")
	)
	(segment
		(start 43.621706 -227.655628)
		(end 43.148504 -227.655628)
		(width 0.20066)
		(layer "F.Cu")
		(net "M_B_CPU1_SB_DQS_DN<5>")
	)
	(segment
		(start 47.060358 -227.491798)
		(end 44.982892 -227.491798)
		(width 0.1016)
		(layer "F.Cu")
		(net "M_B_CPU1_SB_DQS_DN<5>")
	)
	(segment
		(start 47.46371 -227.230686)
		(end 47.202598 -227.491798)
		(width 0.20066)
		(layer "F.Cu")
		(net "M_B_CPU1_SB_DQS_DN<5>")
	)
	(segment
		(start 49.959514 -227.91674)
		(end 49.46904 -227.91674)
		(width 0.20066)
		(layer "F.Cu")
		(net "M_B_CPU1_SB_DQS_DN<5>")
	)
	(segment
		(start 93.314266 -235.506006)
		(end 93.314012 -235.505752)
		(width 0.20066)
		(layer "F.Cu")
		(net "M_B_CPU1_SB_DQS_DN<5>")
	)
	(segment
		(start 73.874884 -233.766106)
		(end 73.874884 -233.590084)
		(width 0.18288)
		(layer "In4.Cu")
		(net "M_B_CPU1_SB_DQS_DN<5>")
	)
	(segment
		(start 56.728868 -227.009198)
		(end 56.05399 -227.009198)
		(width 0.18288)
		(layer "In4.Cu")
		(net "M_B_CPU1_SB_DQS_DN<5>")
	)
	(segment
		(start 53.91531 -226.621086)
		(end 52.711858 -227.824538)
		(width 0.18288)
		(layer "In4.Cu")
		(net "M_B_CPU1_SB_DQS_DN<5>")
	)
	(segment
		(start 59.444382 -224.880678)
		(end 58.80989 -225.51517)
		(width 0.18288)
		(layer "In4.Cu")
		(net "M_B_CPU1_SB_DQS_DN<5>")
	)
	(segment
		(start 82.708496 -234.73283)
		(end 75.01763 -234.73283)
		(width 0.18288)
		(layer "In4.Cu")
		(net "M_B_CPU1_SB_DQS_DN<5>")
	)
	(segment
		(start 83.269582 -234.857544)
		(end 83.084924 -234.672886)
		(width 0.088646)
		(layer "In4.Cu")
		(net "M_B_CPU1_SB_DQS_DN<5>")
	)
	(segment
		(start 63.925196 -225.522282)
		(end 62.517528 -225.522282)
		(width 0.18288)
		(layer "In4.Cu")
		(net "M_B_CPU1_SB_DQS_DN<5>")
	)
	(segment
		(start 72.922892 -232.638092)
		(end 72.535034 -232.250234)
		(width 0.18288)
		(layer "In4.Cu")
		(net "M_B_CPU1_SB_DQS_DN<5>")
	)
	(segment
		(start 71.9709 -231.862122)
		(end 71.9709 -231.6861)
		(width 0.18288)
		(layer "In4.Cu")
		(net "M_B_CPU1_SB_DQS_DN<5>")
	)
	(segment
		(start 86.548214 -234.645708)
		(end 86.533482 -234.654344)
		(width 0.088646)
		(layer "In4.Cu")
		(net "M_B_CPU1_SB_DQS_DN<5>")
	)
	(segment
		(start 93.626686 -234.970066)
		(end 93.68409 -234.912662)
		(width 0.088646)
		(layer "In4.Cu")
		(net "M_B_CPU1_SB_DQS_DN<5>")
	)
	(segment
		(start 64.58331 -226.776534)
		(end 64.58331 -226.180396)
		(width 0.18288)
		(layer "In4.Cu")
		(net "M_B_CPU1_SB_DQS_DN<5>")
	)
	(segment
		(start 72.535034 -232.250234)
		(end 72.359012 -232.250234)
		(width 0.18288)
		(layer "In4.Cu")
		(net "M_B_CPU1_SB_DQS_DN<5>")
	)
	(segment
		(start 73.487026 -233.202226)
		(end 73.311004 -233.202226)
		(width 0.18288)
		(layer "In4.Cu")
		(net "M_B_CPU1_SB_DQS_DN<5>")
	)
	(segment
		(start 60.225686 -224.880678)
		(end 59.444382 -224.880678)
		(width 0.18288)
		(layer "In4.Cu")
		(net "M_B_CPU1_SB_DQS_DN<5>")
	)
	(segment
		(start 71.018908 -230.734108)
		(end 67.536568 -227.251768)
		(width 0.18288)
		(layer "In4.Cu")
		(net "M_B_CPU1_SB_DQS_DN<5>")
	)
	(segment
		(start 74.26325 -234.154472)
		(end 73.874884 -233.766106)
		(width 0.18288)
		(layer "In4.Cu")
		(net "M_B_CPU1_SB_DQS_DN<5>")
	)
	(segment
		(start 62.517528 -225.522282)
		(end 62.248288 -225.791522)
		(width 0.18288)
		(layer "In4.Cu")
		(net "M_B_CPU1_SB_DQS_DN<5>")
	)
	(segment
		(start 89.367614 -234.645708)
		(end 89.352882 -234.654344)
		(width 0.088646)
		(layer "In4.Cu")
		(net "M_B_CPU1_SB_DQS_DN<5>")
	)
	(segment
		(start 61.860176 -225.791522)
		(end 61.592206 -225.523552)
		(width 0.18288)
		(layer "In4.Cu")
		(net "M_B_CPU1_SB_DQS_DN<5>")
	)
	(segment
		(start 56.05399 -227.009198)
		(end 55.665878 -226.621086)
		(width 0.18288)
		(layer "In4.Cu")
		(net "M_B_CPU1_SB_DQS_DN<5>")
	)
	(segment
		(start 92.187014 -234.645708)
		(end 92.172282 -234.654344)
		(width 0.088646)
		(layer "In4.Cu")
		(net "M_B_CPU1_SB_DQS_DN<5>")
	)
	(segment
		(start 66.38671 -227.494338)
		(end 65.956688 -227.494338)
		(width 0.18288)
		(layer "In4.Cu")
		(net "M_B_CPU1_SB_DQS_DN<5>")
	)
	(segment
		(start 62.248288 -225.791522)
		(end 61.860176 -225.791522)
		(width 0.18288)
		(layer "In4.Cu")
		(net "M_B_CPU1_SB_DQS_DN<5>")
	)
	(segment
		(start 91.247214 -234.645708)
		(end 91.2368 -234.651804)
		(width 0.088646)
		(layer "In4.Cu")
		(net "M_B_CPU1_SB_DQS_DN<5>")
	)
	(segment
		(start 71.583042 -231.298242)
		(end 71.40702 -231.298242)
		(width 0.18288)
		(layer "In4.Cu")
		(net "M_B_CPU1_SB_DQS_DN<5>")
	)
	(segment
		(start 51.087782 -227.91674)
		(end 51.064414 -227.91674)
		(width 0.18288)
		(layer "In4.Cu")
		(net "M_B_CPU1_SB_DQS_DN<5>")
	)
	(segment
		(start 83.694016 -234.857544)
		(end 83.269582 -234.857544)
		(width 0.088646)
		(layer "In4.Cu")
		(net "M_B_CPU1_SB_DQS_DN<5>")
	)
	(segment
		(start 87.488014 -234.645708)
		(end 87.473282 -234.654344)
		(width 0.088646)
		(layer "In4.Cu")
		(net "M_B_CPU1_SB_DQS_DN<5>")
	)
	(segment
		(start 85.608414 -234.645708)
		(end 85.593682 -234.654344)
		(width 0.088646)
		(layer "In4.Cu")
		(net "M_B_CPU1_SB_DQS_DN<5>")
	)
	(segment
		(start 65.04051 -227.233734)
		(end 64.58331 -226.776534)
		(width 0.18288)
		(layer "In4.Cu")
		(net "M_B_CPU1_SB_DQS_DN<5>")
	)
	(segment
		(start 55.665878 -226.621086)
		(end 53.91531 -226.621086)
		(width 0.18288)
		(layer "In4.Cu")
		(net "M_B_CPU1_SB_DQS_DN<5>")
	)
	(segment
		(start 72.922892 -232.814114)
		(end 72.922892 -232.638092)
		(width 0.18288)
		(layer "In4.Cu")
		(net "M_B_CPU1_SB_DQS_DN<5>")
	)
	(segment
		(start 51.310794 -227.824538)
		(end 51.087782 -227.91674)
		(width 0.18288)
		(layer "In4.Cu")
		(net "M_B_CPU1_SB_DQS_DN<5>")
	)
	(segment
		(start 93.314012 -234.970066)
		(end 93.626686 -234.970066)
		(width 0.088646)
		(layer "In4.Cu")
		(net "M_B_CPU1_SB_DQS_DN<5>")
	)
	(segment
		(start 73.311004 -233.202226)
		(end 72.922892 -232.814114)
		(width 0.18288)
		(layer "In4.Cu")
		(net "M_B_CPU1_SB_DQS_DN<5>")
	)
	(segment
		(start 71.018908 -230.91013)
		(end 71.018908 -230.734108)
		(width 0.18288)
		(layer "In4.Cu")
		(net "M_B_CPU1_SB_DQS_DN<5>")
	)
	(segment
		(start 71.40702 -231.298242)
		(end 71.018908 -230.91013)
		(width 0.18288)
		(layer "In4.Cu")
		(net "M_B_CPU1_SB_DQS_DN<5>")
	)
	(segment
		(start 72.359012 -232.250234)
		(end 71.9709 -231.862122)
		(width 0.18288)
		(layer "In4.Cu")
		(net "M_B_CPU1_SB_DQS_DN<5>")
	)
	(segment
		(start 61.592206 -225.523552)
		(end 60.86856 -225.523552)
		(width 0.18288)
		(layer "In4.Cu")
		(net "M_B_CPU1_SB_DQS_DN<5>")
	)
	(segment
		(start 73.874884 -233.590084)
		(end 73.487026 -233.202226)
		(width 0.18288)
		(layer "In4.Cu")
		(net "M_B_CPU1_SB_DQS_DN<5>")
	)
	(segment
		(start 58.80989 -225.51517)
		(end 58.222896 -225.51517)
		(width 0.18288)
		(layer "In4.Cu")
		(net "M_B_CPU1_SB_DQS_DN<5>")
	)
	(segment
		(start 74.439272 -234.154472)
		(end 74.26325 -234.154472)
		(width 0.18288)
		(layer "In4.Cu")
		(net "M_B_CPU1_SB_DQS_DN<5>")
	)
	(segment
		(start 52.711858 -227.824538)
		(end 51.310794 -227.824538)
		(width 0.18288)
		(layer "In4.Cu")
		(net "M_B_CPU1_SB_DQS_DN<5>")
	)
	(segment
		(start 65.956688 -227.494338)
		(end 65.696084 -227.233734)
		(width 0.18288)
		(layer "In4.Cu")
		(net "M_B_CPU1_SB_DQS_DN<5>")
	)
	(segment
		(start 67.536568 -227.251768)
		(end 66.62928 -227.251768)
		(width 0.18288)
		(layer "In4.Cu")
		(net "M_B_CPU1_SB_DQS_DN<5>")
	)
	(segment
		(start 93.126814 -234.645708)
		(end 93.112082 -234.654344)
		(width 0.088646)
		(layer "In4.Cu")
		(net "M_B_CPU1_SB_DQS_DN<5>")
	)
	(segment
		(start 83.084924 -234.672886)
		(end 82.803746 -234.672886)
		(width 0.088646)
		(layer "In4.Cu")
		(net "M_B_CPU1_SB_DQS_DN<5>")
	)
	(segment
		(start 83.83016 -234.7214)
		(end 83.694016 -234.857544)
		(width 0.088646)
		(layer "In4.Cu")
		(net "M_B_CPU1_SB_DQS_DN<5>")
	)
	(segment
		(start 71.9709 -231.6861)
		(end 71.583042 -231.298242)
		(width 0.18288)
		(layer "In4.Cu")
		(net "M_B_CPU1_SB_DQS_DN<5>")
	)
	(segment
		(start 75.01763 -234.73283)
		(end 74.439272 -234.154472)
		(width 0.18288)
		(layer "In4.Cu")
		(net "M_B_CPU1_SB_DQS_DN<5>")
	)
	(segment
		(start 60.86856 -225.523552)
		(end 60.225686 -224.880678)
		(width 0.18288)
		(layer "In4.Cu")
		(net "M_B_CPU1_SB_DQS_DN<5>")
	)
	(segment
		(start 88.427814 -234.645708)
		(end 88.413082 -234.654344)
		(width 0.088646)
		(layer "In4.Cu")
		(net "M_B_CPU1_SB_DQS_DN<5>")
	)
	(segment
		(start 65.696084 -227.233734)
		(end 65.04051 -227.233734)
		(width 0.18288)
		(layer "In4.Cu")
		(net "M_B_CPU1_SB_DQS_DN<5>")
	)
	(segment
		(start 64.58331 -226.180396)
		(end 63.925196 -225.522282)
		(width 0.18288)
		(layer "In4.Cu")
		(net "M_B_CPU1_SB_DQS_DN<5>")
	)
	(segment
		(start 66.62928 -227.251768)
		(end 66.38671 -227.494338)
		(width 0.18288)
		(layer "In4.Cu")
		(net "M_B_CPU1_SB_DQS_DN<5>")
	)
	(segment
		(start 58.222896 -225.51517)
		(end 56.728868 -227.009198)
		(width 0.18288)
		(layer "In4.Cu")
		(net "M_B_CPU1_SB_DQS_DN<5>")
	)
	(segment
		(start 82.743802 -234.73283)
		(end 82.708496 -234.73283)
		(width 0.088646)
		(layer "In4.Cu")
		(net "M_B_CPU1_SB_DQS_DN<5>")
	)
	(segment
		(start 84.38642 -234.7214)
		(end 83.83016 -234.7214)
		(width 0.088646)
		(layer "In4.Cu")
		(net "M_B_CPU1_SB_DQS_DN<5>")
	)
	(segment
		(start 90.307668 -234.645708)
		(end 90.297254 -234.651804)
		(width 0.088646)
		(layer "In4.Cu")
		(net "M_B_CPU1_SB_DQS_DN<5>")
	)
	(segment
		(start 82.803746 -234.672886)
		(end 82.743802 -234.73283)
		(width 0.088646)
		(layer "In4.Cu")
		(net "M_B_CPU1_SB_DQS_DN<5>")
	)
	(arc
		(start 88.80221 -234.645708)
		(mid 88.615012 -234.595565)
		(end 88.427814 -234.645708)
		(width 0.088646)
		(layer "In4.Cu")
		(net "M_B_CPU1_SB_DQS_DN<5>")
	)
	(arc
		(start 85.98281 -234.645708)
		(mid 85.795612 -234.595565)
		(end 85.608414 -234.645708)
		(width 0.088646)
		(layer "In4.Cu")
		(net "M_B_CPU1_SB_DQS_DN<5>")
	)
	(arc
		(start 93.112082 -234.654344)
		(mid 92.835607 -234.721664)
		(end 92.56141 -234.645708)
		(width 0.088646)
		(layer "In4.Cu")
		(net "M_B_CPU1_SB_DQS_DN<5>")
	)
	(arc
		(start 90.297254 -234.651804)
		(mid 90.018822 -234.72165)
		(end 89.74201 -234.645708)
		(width 0.088646)
		(layer "In4.Cu")
		(net "M_B_CPU1_SB_DQS_DN<5>")
	)
	(arc
		(start 87.86241 -234.645708)
		(mid 87.675212 -234.595565)
		(end 87.488014 -234.645708)
		(width 0.088646)
		(layer "In4.Cu")
		(net "M_B_CPU1_SB_DQS_DN<5>")
	)
	(arc
		(start 91.62161 -234.645708)
		(mid 91.434412 -234.595565)
		(end 91.247214 -234.645708)
		(width 0.088646)
		(layer "In4.Cu")
		(net "M_B_CPU1_SB_DQS_DN<5>")
	)
	(arc
		(start 86.533482 -234.654344)
		(mid 86.257007 -234.721664)
		(end 85.98281 -234.645708)
		(width 0.088646)
		(layer "In4.Cu")
		(net "M_B_CPU1_SB_DQS_DN<5>")
	)
	(arc
		(start 92.56141 -234.645708)
		(mid 92.374212 -234.595565)
		(end 92.187014 -234.645708)
		(width 0.088646)
		(layer "In4.Cu")
		(net "M_B_CPU1_SB_DQS_DN<5>")
	)
	(arc
		(start 90.682064 -234.645708)
		(mid 90.494866 -234.595565)
		(end 90.307668 -234.645708)
		(width 0.088646)
		(layer "In4.Cu")
		(net "M_B_CPU1_SB_DQS_DN<5>")
	)
	(arc
		(start 87.473282 -234.654344)
		(mid 87.196807 -234.721664)
		(end 86.92261 -234.645708)
		(width 0.088646)
		(layer "In4.Cu")
		(net "M_B_CPU1_SB_DQS_DN<5>")
	)
	(arc
		(start 93.68409 -234.912662)
		(mid 93.475807 -234.632316)
		(end 93.126814 -234.645708)
		(width 0.088646)
		(layer "In4.Cu")
		(net "M_B_CPU1_SB_DQS_DN<5>")
	)
	(arc
		(start 85.593682 -234.654344)
		(mid 85.317207 -234.721664)
		(end 85.04301 -234.645708)
		(width 0.088646)
		(layer "In4.Cu")
		(net "M_B_CPU1_SB_DQS_DN<5>")
	)
	(arc
		(start 85.04301 -234.645708)
		(mid 84.855812 -234.595565)
		(end 84.668614 -234.645708)
		(width 0.088646)
		(layer "In4.Cu")
		(net "M_B_CPU1_SB_DQS_DN<5>")
	)
	(arc
		(start 86.92261 -234.645708)
		(mid 86.735412 -234.595565)
		(end 86.548214 -234.645708)
		(width 0.088646)
		(layer "In4.Cu")
		(net "M_B_CPU1_SB_DQS_DN<5>")
	)
	(arc
		(start 92.172282 -234.654344)
		(mid 91.895807 -234.721664)
		(end 91.62161 -234.645708)
		(width 0.088646)
		(layer "In4.Cu")
		(net "M_B_CPU1_SB_DQS_DN<5>")
	)
	(arc
		(start 89.74201 -234.645708)
		(mid 89.554812 -234.595565)
		(end 89.367614 -234.645708)
		(width 0.088646)
		(layer "In4.Cu")
		(net "M_B_CPU1_SB_DQS_DN<5>")
	)
	(arc
		(start 89.352882 -234.654344)
		(mid 89.076407 -234.721664)
		(end 88.80221 -234.645708)
		(width 0.088646)
		(layer "In4.Cu")
		(net "M_B_CPU1_SB_DQS_DN<5>")
	)
	(arc
		(start 91.2368 -234.651804)
		(mid 90.958622 -234.721527)
		(end 90.682064 -234.645708)
		(width 0.088646)
		(layer "In4.Cu")
		(net "M_B_CPU1_SB_DQS_DN<5>")
	)
	(arc
		(start 84.668614 -234.645708)
		(mid 84.53249 -234.702084)
		(end 84.38642 -234.7214)
		(width 0.088646)
		(layer "In4.Cu")
		(net "M_B_CPU1_SB_DQS_DN<5>")
	)
	(arc
		(start 88.413082 -234.654344)
		(mid 88.136607 -234.721664)
		(end 87.86241 -234.645708)
		(width 0.088646)
		(layer "In4.Cu")
		(net "M_B_CPU1_SB_DQS_DN<5>")
	)
	(segment
		(start 44.55033 -236.849666)
		(end 44.283884 -236.58322)
		(width 0.20066)
		(layer "F.Cu")
		(net "M_B_CPU1_SB_DQS_DN<4>")
	)
	(segment
		(start 44.283884 -236.58322)
		(end 44.044108 -236.58322)
		(width 0.20066)
		(layer "F.Cu")
		(net "M_B_CPU1_SB_DQS_DN<4>")
	)
	(segment
		(start 44.982892 -236.841792)
		(end 44.743116 -236.841792)
		(width 0.101854)
		(layer "F.Cu")
		(net "M_B_CPU1_SB_DQS_DN<4>")
	)
	(segment
		(start 49.959514 -237.266734)
		(end 49.46904 -237.266734)
		(width 0.20066)
		(layer "F.Cu")
		(net "M_B_CPU1_SB_DQS_DN<4>")
	)
	(segment
		(start 49.207928 -237.005622)
		(end 48.504348 -237.005622)
		(width 0.20066)
		(layer "F.Cu")
		(net "M_B_CPU1_SB_DQS_DN<4>")
	)
	(segment
		(start 47.46371 -236.58068)
		(end 47.202598 -236.841792)
		(width 0.20066)
		(layer "F.Cu")
		(net "M_B_CPU1_SB_DQS_DN<4>")
	)
	(segment
		(start 44.735242 -236.849666)
		(end 44.55033 -236.849666)
		(width 0.20066)
		(layer "F.Cu")
		(net "M_B_CPU1_SB_DQS_DN<4>")
	)
	(segment
		(start 48.504348 -237.005622)
		(end 47.868332 -236.58068)
		(width 0.20066)
		(layer "F.Cu")
		(net "M_B_CPU1_SB_DQS_DN<4>")
	)
	(segment
		(start 43.148504 -237.005622)
		(end 42.887392 -237.266734)
		(width 0.20066)
		(layer "F.Cu")
		(net "M_B_CPU1_SB_DQS_DN<4>")
	)
	(segment
		(start 51.064414 -237.266734)
		(end 49.959514 -237.266734)
		(width 0.20066)
		(layer "F.Cu")
		(net "M_B_CPU1_SB_DQS_DN<4>")
	)
	(segment
		(start 47.060358 -236.841792)
		(end 44.982892 -236.841792)
		(width 0.1016)
		(layer "F.Cu")
		(net "M_B_CPU1_SB_DQS_DN<4>")
	)
	(segment
		(start 47.202598 -236.841792)
		(end 47.060358 -236.841792)
		(width 0.20066)
		(layer "F.Cu")
		(net "M_B_CPU1_SB_DQS_DN<4>")
	)
	(segment
		(start 44.044108 -236.58322)
		(end 43.621706 -237.005622)
		(width 0.20066)
		(layer "F.Cu")
		(net "M_B_CPU1_SB_DQS_DN<4>")
	)
	(segment
		(start 90.964512 -242.830858)
		(end 90.964512 -242.295172)
		(width 0.20066)
		(layer "F.Cu")
		(net "M_B_CPU1_SB_DQS_DN<4>")
	)
	(segment
		(start 44.743116 -236.841792)
		(end 44.735242 -236.849666)
		(width 0.101854)
		(layer "F.Cu")
		(net "M_B_CPU1_SB_DQS_DN<4>")
	)
	(segment
		(start 90.964512 -242.295172)
		(end 90.964766 -242.294918)
		(width 0.20066)
		(layer "F.Cu")
		(net "M_B_CPU1_SB_DQS_DN<4>")
	)
	(segment
		(start 43.621706 -237.005622)
		(end 43.148504 -237.005622)
		(width 0.20066)
		(layer "F.Cu")
		(net "M_B_CPU1_SB_DQS_DN<4>")
	)
	(segment
		(start 49.46904 -237.266734)
		(end 49.207928 -237.005622)
		(width 0.20066)
		(layer "F.Cu")
		(net "M_B_CPU1_SB_DQS_DN<4>")
	)
	(segment
		(start 42.887392 -237.266734)
		(end 42.415714 -237.266734)
		(width 0.20066)
		(layer "F.Cu")
		(net "M_B_CPU1_SB_DQS_DN<4>")
	)
	(segment
		(start 47.868332 -236.58068)
		(end 47.46371 -236.58068)
		(width 0.20066)
		(layer "F.Cu")
		(net "M_B_CPU1_SB_DQS_DN<4>")
	)
	(segment
		(start 62.120272 -238.480092)
		(end 61.92012 -238.680244)
		(width 0.16002)
		(layer "In2.Cu")
		(net "M_B_CPU1_SB_DQS_DN<4>")
	)
	(segment
		(start 90.307414 -242.78463)
		(end 90.292682 -242.793266)
		(width 0.088646)
		(layer "In2.Cu")
		(net "M_B_CPU1_SB_DQS_DN<4>")
	)
	(segment
		(start 65.991994 -237.874302)
		(end 65.81013 -238.056166)
		(width 0.18288)
		(layer "In2.Cu")
		(net "M_B_CPU1_SB_DQS_DN<4>")
	)
	(segment
		(start 63.860426 -237.632494)
		(end 63.731902 -237.50397)
		(width 0.18288)
		(layer "In2.Cu")
		(net "M_B_CPU1_SB_DQS_DN<4>")
	)
	(segment
		(start 66.020188 -237.846108)
		(end 65.991994 -237.874302)
		(width 0.16002)
		(layer "In2.Cu")
		(net "M_B_CPU1_SB_DQS_DN<4>")
	)
	(segment
		(start 60.004452 -238.710724)
		(end 59.8043 -238.510572)
		(width 0.16002)
		(layer "In2.Cu")
		(net "M_B_CPU1_SB_DQS_DN<4>")
	)
	(segment
		(start 61.710062 -238.90605)
		(end 60.18403 -238.90605)
		(width 0.18288)
		(layer "In2.Cu")
		(net "M_B_CPU1_SB_DQS_DN<4>")
	)
	(segment
		(start 83.123786 -242.781836)
		(end 83.064096 -242.841526)
		(width 0.088646)
		(layer "In2.Cu")
		(net "M_B_CPU1_SB_DQS_DN<4>")
	)
	(segment
		(start 60.032646 -238.754666)
		(end 60.004452 -238.726472)
		(width 0.16002)
		(layer "In2.Cu")
		(net "M_B_CPU1_SB_DQS_DN<4>")
	)
	(segment
		(start 83.914234 -242.733322)
		(end 83.63204 -242.733322)
		(width 0.088646)
		(layer "In2.Cu")
		(net "M_B_CPU1_SB_DQS_DN<4>")
	)
	(segment
		(start 64.132714 -237.904782)
		(end 64.10452 -237.876588)
		(width 0.16002)
		(layer "In2.Cu")
		(net "M_B_CPU1_SB_DQS_DN<4>")
	)
	(segment
		(start 63.88862 -237.660688)
		(end 63.860426 -237.632494)
		(width 0.16002)
		(layer "In2.Cu")
		(net "M_B_CPU1_SB_DQS_DN<4>")
	)
	(segment
		(start 69.710808 -238.949992)
		(end 67.2719 -237.939834)
		(width 0.18288)
		(layer "In2.Cu")
		(net "M_B_CPU1_SB_DQS_DN<4>")
	)
	(segment
		(start 59.8043 -238.510572)
		(end 59.788552 -238.510572)
		(width 0.16002)
		(layer "In2.Cu")
		(net "M_B_CPU1_SB_DQS_DN<4>")
	)
	(segment
		(start 59.788552 -238.510572)
		(end 59.760358 -238.482378)
		(width 0.16002)
		(layer "In2.Cu")
		(net "M_B_CPU1_SB_DQS_DN<4>")
	)
	(segment
		(start 63.904368 -237.660688)
		(end 63.88862 -237.660688)
		(width 0.16002)
		(layer "In2.Cu")
		(net "M_B_CPU1_SB_DQS_DN<4>")
	)
	(segment
		(start 58.476388 -237.846108)
		(end 58.448194 -237.874302)
		(width 0.16002)
		(layer "In2.Cu")
		(net "M_B_CPU1_SB_DQS_DN<4>")
	)
	(segment
		(start 66.402966 -237.46333)
		(end 66.264282 -237.602014)
		(width 0.18288)
		(layer "In2.Cu")
		(net "M_B_CPU1_SB_DQS_DN<4>")
	)
	(segment
		(start 89.367614 -242.78463)
		(end 89.352882 -242.793266)
		(width 0.088646)
		(layer "In2.Cu")
		(net "M_B_CPU1_SB_DQS_DN<4>")
	)
	(segment
		(start 83.064096 -242.841526)
		(end 74.644758 -242.841526)
		(width 0.18288)
		(layer "In2.Cu")
		(net "M_B_CPU1_SB_DQS_DN<4>")
	)
	(segment
		(start 62.13602 -238.480092)
		(end 62.120272 -238.480092)
		(width 0.16002)
		(layer "In2.Cu")
		(net "M_B_CPU1_SB_DQS_DN<4>")
	)
	(segment
		(start 52.783994 -236.769402)
		(end 52.767738 -236.769402)
		(width 0.16002)
		(layer "In2.Cu")
		(net "M_B_CPU1_SB_DQS_DN<4>")
	)
	(segment
		(start 84.66328 -242.787932)
		(end 84.65693 -242.791488)
		(width 0.088646)
		(layer "In2.Cu")
		(net "M_B_CPU1_SB_DQS_DN<4>")
	)
	(segment
		(start 64.284098 -238.056166)
		(end 64.132714 -237.904782)
		(width 0.18288)
		(layer "In2.Cu")
		(net "M_B_CPU1_SB_DQS_DN<4>")
	)
	(segment
		(start 88.428068 -242.78463)
		(end 88.413336 -242.793266)
		(width 0.088646)
		(layer "In2.Cu")
		(net "M_B_CPU1_SB_DQS_DN<4>")
	)
	(segment
		(start 66.264282 -237.602014)
		(end 66.236088 -237.630208)
		(width 0.16002)
		(layer "In2.Cu")
		(net "M_B_CPU1_SB_DQS_DN<4>")
	)
	(segment
		(start 59.760358 -238.482378)
		(end 59.425078 -238.147098)
		(width 0.18288)
		(layer "In2.Cu")
		(net "M_B_CPU1_SB_DQS_DN<4>")
	)
	(segment
		(start 56.286146 -237.602014)
		(end 55.903622 -237.21949)
		(width 0.18288)
		(layer "In2.Cu")
		(net "M_B_CPU1_SB_DQS_DN<4>")
	)
	(segment
		(start 55.903622 -237.21949)
		(end 54.472586 -237.21949)
		(width 0.18288)
		(layer "In2.Cu")
		(net "M_B_CPU1_SB_DQS_DN<4>")
	)
	(segment
		(start 56.53024 -237.846108)
		(end 56.53024 -237.83036)
		(width 0.16002)
		(layer "In2.Cu")
		(net "M_B_CPU1_SB_DQS_DN<4>")
	)
	(segment
		(start 52.568094 -236.985302)
		(end 52.5399 -237.013496)
		(width 0.16002)
		(layer "In2.Cu")
		(net "M_B_CPU1_SB_DQS_DN<4>")
	)
	(segment
		(start 88.434418 -242.78082)
		(end 88.428068 -242.78463)
		(width 0.088646)
		(layer "In2.Cu")
		(net "M_B_CPU1_SB_DQS_DN<4>")
	)
	(segment
		(start 66.558922 -237.46333)
		(end 66.402966 -237.46333)
		(width 0.18288)
		(layer "In2.Cu")
		(net "M_B_CPU1_SB_DQS_DN<4>")
	)
	(segment
		(start 90.964766 -242.294918)
		(end 90.651838 -242.294918)
		(width 0.088646)
		(layer "In2.Cu")
		(net "M_B_CPU1_SB_DQS_DN<4>")
	)
	(segment
		(start 56.53024 -237.83036)
		(end 56.330088 -237.630208)
		(width 0.16002)
		(layer "In2.Cu")
		(net "M_B_CPU1_SB_DQS_DN<4>")
	)
	(segment
		(start 83.63204 -242.733322)
		(end 83.583526 -242.781836)
		(width 0.088646)
		(layer "In2.Cu")
		(net "M_B_CPU1_SB_DQS_DN<4>")
	)
	(segment
		(start 54.240938 -236.971586)
		(end 54.041294 -236.771942)
		(width 0.16002)
		(layer "In2.Cu")
		(net "M_B_CPU1_SB_DQS_DN<4>")
	)
	(segment
		(start 58.448194 -237.874302)
		(end 58.283602 -238.038894)
		(width 0.18288)
		(layer "In2.Cu")
		(net "M_B_CPU1_SB_DQS_DN<4>")
	)
	(segment
		(start 88.43645 -242.779804)
		(end 88.434418 -242.78082)
		(width 0.088646)
		(layer "In2.Cu")
		(net "M_B_CPU1_SB_DQS_DN<4>")
	)
	(segment
		(start 59.425078 -237.845346)
		(end 59.089798 -237.510066)
		(width 0.18288)
		(layer "In2.Cu")
		(net "M_B_CPU1_SB_DQS_DN<4>")
	)
	(segment
		(start 61.92012 -238.680244)
		(end 61.92012 -238.695992)
		(width 0.16002)
		(layer "In2.Cu")
		(net "M_B_CPU1_SB_DQS_DN<4>")
	)
	(segment
		(start 53.799486 -236.54639)
		(end 53.007006 -236.54639)
		(width 0.18288)
		(layer "In2.Cu")
		(net "M_B_CPU1_SB_DQS_DN<4>")
	)
	(segment
		(start 66.020188 -237.83036)
		(end 66.020188 -237.846108)
		(width 0.16002)
		(layer "In2.Cu")
		(net "M_B_CPU1_SB_DQS_DN<4>")
	)
	(segment
		(start 54.240938 -236.987842)
		(end 54.240938 -236.971586)
		(width 0.16002)
		(layer "In2.Cu")
		(net "M_B_CPU1_SB_DQS_DN<4>")
	)
	(segment
		(start 58.81243 -237.510066)
		(end 58.720482 -237.602014)
		(width 0.18288)
		(layer "In2.Cu")
		(net "M_B_CPU1_SB_DQS_DN<4>")
	)
	(segment
		(start 51.724814 -237.17631)
		(end 51.529488 -236.980984)
		(width 0.18288)
		(layer "In2.Cu")
		(net "M_B_CPU1_SB_DQS_DN<4>")
	)
	(segment
		(start 56.558434 -237.874302)
		(end 56.53024 -237.846108)
		(width 0.16002)
		(layer "In2.Cu")
		(net "M_B_CPU1_SB_DQS_DN<4>")
	)
	(segment
		(start 56.723026 -238.038894)
		(end 56.558434 -237.874302)
		(width 0.18288)
		(layer "In2.Cu")
		(net "M_B_CPU1_SB_DQS_DN<4>")
	)
	(segment
		(start 52.5399 -237.013496)
		(end 52.377086 -237.17631)
		(width 0.18288)
		(layer "In2.Cu")
		(net "M_B_CPU1_SB_DQS_DN<4>")
	)
	(segment
		(start 64.10452 -237.876588)
		(end 64.10452 -237.86084)
		(width 0.16002)
		(layer "In2.Cu")
		(net "M_B_CPU1_SB_DQS_DN<4>")
	)
	(segment
		(start 90.651838 -242.294918)
		(end 90.58656 -242.360196)
		(width 0.088646)
		(layer "In2.Cu")
		(net "M_B_CPU1_SB_DQS_DN<4>")
	)
	(segment
		(start 54.472586 -237.21949)
		(end 54.269132 -237.016036)
		(width 0.18288)
		(layer "In2.Cu")
		(net "M_B_CPU1_SB_DQS_DN<4>")
	)
	(segment
		(start 53.007006 -236.54639)
		(end 52.812188 -236.741208)
		(width 0.18288)
		(layer "In2.Cu")
		(net "M_B_CPU1_SB_DQS_DN<4>")
	)
	(segment
		(start 85.607906 -242.78463)
		(end 85.597492 -242.790726)
		(width 0.088646)
		(layer "In2.Cu")
		(net "M_B_CPU1_SB_DQS_DN<4>")
	)
	(segment
		(start 61.891926 -238.724186)
		(end 61.710062 -238.90605)
		(width 0.18288)
		(layer "In2.Cu")
		(net "M_B_CPU1_SB_DQS_DN<4>")
	)
	(segment
		(start 54.269132 -237.016036)
		(end 54.240938 -236.987842)
		(width 0.16002)
		(layer "In2.Cu")
		(net "M_B_CPU1_SB_DQS_DN<4>")
	)
	(segment
		(start 86.548214 -242.78463)
		(end 86.53018 -242.795044)
		(width 0.088646)
		(layer "In2.Cu")
		(net "M_B_CPU1_SB_DQS_DN<4>")
	)
	(segment
		(start 62.164214 -238.451898)
		(end 62.13602 -238.480092)
		(width 0.16002)
		(layer "In2.Cu")
		(net "M_B_CPU1_SB_DQS_DN<4>")
	)
	(segment
		(start 58.720482 -237.602014)
		(end 58.692288 -237.630208)
		(width 0.16002)
		(layer "In2.Cu")
		(net "M_B_CPU1_SB_DQS_DN<4>")
	)
	(segment
		(start 69.711062 -238.949992)
		(end 69.710808 -238.949992)
		(width 0.18288)
		(layer "In2.Cu")
		(net "M_B_CPU1_SB_DQS_DN<4>")
	)
	(segment
		(start 67.2719 -237.939834)
		(end 66.558922 -237.46333)
		(width 0.18288)
		(layer "In2.Cu")
		(net "M_B_CPU1_SB_DQS_DN<4>")
	)
	(segment
		(start 51.529488 -236.980984)
		(end 51.350164 -236.980984)
		(width 0.18288)
		(layer "In2.Cu")
		(net "M_B_CPU1_SB_DQS_DN<4>")
	)
	(segment
		(start 52.568094 -236.969046)
		(end 52.568094 -236.985302)
		(width 0.16002)
		(layer "In2.Cu")
		(net "M_B_CPU1_SB_DQS_DN<4>")
	)
	(segment
		(start 85.622384 -242.776248)
		(end 85.607906 -242.78463)
		(width 0.088646)
		(layer "In2.Cu")
		(net "M_B_CPU1_SB_DQS_DN<4>")
	)
	(segment
		(start 58.692288 -237.630208)
		(end 58.67654 -237.630208)
		(width 0.16002)
		(layer "In2.Cu")
		(net "M_B_CPU1_SB_DQS_DN<4>")
	)
	(segment
		(start 59.089798 -237.510066)
		(end 58.81243 -237.510066)
		(width 0.18288)
		(layer "In2.Cu")
		(net "M_B_CPU1_SB_DQS_DN<4>")
	)
	(segment
		(start 52.767738 -236.769402)
		(end 52.568094 -236.969046)
		(width 0.16002)
		(layer "In2.Cu")
		(net "M_B_CPU1_SB_DQS_DN<4>")
	)
	(segment
		(start 54.041294 -236.771942)
		(end 54.025038 -236.771942)
		(width 0.16002)
		(layer "In2.Cu")
		(net "M_B_CPU1_SB_DQS_DN<4>")
	)
	(segment
		(start 58.67654 -237.630208)
		(end 58.476388 -237.83036)
		(width 0.16002)
		(layer "In2.Cu")
		(net "M_B_CPU1_SB_DQS_DN<4>")
	)
	(segment
		(start 84.668868 -242.78463)
		(end 84.66328 -242.787932)
		(width 0.088646)
		(layer "In2.Cu")
		(net "M_B_CPU1_SB_DQS_DN<4>")
	)
	(segment
		(start 66.22034 -237.630208)
		(end 66.020188 -237.83036)
		(width 0.16002)
		(layer "In2.Cu")
		(net "M_B_CPU1_SB_DQS_DN<4>")
	)
	(segment
		(start 64.10452 -237.86084)
		(end 63.904368 -237.660688)
		(width 0.16002)
		(layer "In2.Cu")
		(net "M_B_CPU1_SB_DQS_DN<4>")
	)
	(segment
		(start 60.18403 -238.90605)
		(end 60.032646 -238.754666)
		(width 0.18288)
		(layer "In2.Cu")
		(net "M_B_CPU1_SB_DQS_DN<4>")
	)
	(segment
		(start 52.812188 -236.741208)
		(end 52.783994 -236.769402)
		(width 0.16002)
		(layer "In2.Cu")
		(net "M_B_CPU1_SB_DQS_DN<4>")
	)
	(segment
		(start 51.350164 -236.980984)
		(end 51.064414 -237.266734)
		(width 0.18288)
		(layer "In2.Cu")
		(net "M_B_CPU1_SB_DQS_DN<4>")
	)
	(segment
		(start 52.377086 -237.17631)
		(end 51.724814 -237.17631)
		(width 0.18288)
		(layer "In2.Cu")
		(net "M_B_CPU1_SB_DQS_DN<4>")
	)
	(segment
		(start 56.330088 -237.630208)
		(end 56.31434 -237.630208)
		(width 0.16002)
		(layer "In2.Cu")
		(net "M_B_CPU1_SB_DQS_DN<4>")
	)
	(segment
		(start 59.425078 -238.147098)
		(end 59.425078 -237.845346)
		(width 0.18288)
		(layer "In2.Cu")
		(net "M_B_CPU1_SB_DQS_DN<4>")
	)
	(segment
		(start 83.583526 -242.781836)
		(end 83.123786 -242.781836)
		(width 0.088646)
		(layer "In2.Cu")
		(net "M_B_CPU1_SB_DQS_DN<4>")
	)
	(segment
		(start 63.731902 -237.50397)
		(end 63.112142 -237.50397)
		(width 0.18288)
		(layer "In2.Cu")
		(net "M_B_CPU1_SB_DQS_DN<4>")
	)
	(segment
		(start 63.112142 -237.50397)
		(end 62.164214 -238.451898)
		(width 0.18288)
		(layer "In2.Cu")
		(net "M_B_CPU1_SB_DQS_DN<4>")
	)
	(segment
		(start 74.43089 -242.627912)
		(end 71.489316 -239.686592)
		(width 0.18288)
		(layer "In2.Cu")
		(net "M_B_CPU1_SB_DQS_DN<4>")
	)
	(segment
		(start 60.004452 -238.726472)
		(end 60.004452 -238.710724)
		(width 0.16002)
		(layer "In2.Cu")
		(net "M_B_CPU1_SB_DQS_DN<4>")
	)
	(segment
		(start 56.31434 -237.630208)
		(end 56.286146 -237.602014)
		(width 0.16002)
		(layer "In2.Cu")
		(net "M_B_CPU1_SB_DQS_DN<4>")
	)
	(segment
		(start 53.996844 -236.743748)
		(end 53.799486 -236.54639)
		(width 0.18288)
		(layer "In2.Cu")
		(net "M_B_CPU1_SB_DQS_DN<4>")
	)
	(segment
		(start 58.476388 -237.83036)
		(end 58.476388 -237.846108)
		(width 0.16002)
		(layer "In2.Cu")
		(net "M_B_CPU1_SB_DQS_DN<4>")
	)
	(segment
		(start 58.283602 -238.038894)
		(end 56.723026 -238.038894)
		(width 0.18288)
		(layer "In2.Cu")
		(net "M_B_CPU1_SB_DQS_DN<4>")
	)
	(segment
		(start 74.644758 -242.841526)
		(end 74.43089 -242.627912)
		(width 0.18288)
		(layer "In2.Cu")
		(net "M_B_CPU1_SB_DQS_DN<4>")
	)
	(segment
		(start 71.489316 -239.686592)
		(end 69.711062 -238.949992)
		(width 0.18288)
		(layer "In2.Cu")
		(net "M_B_CPU1_SB_DQS_DN<4>")
	)
	(segment
		(start 66.236088 -237.630208)
		(end 66.22034 -237.630208)
		(width 0.16002)
		(layer "In2.Cu")
		(net "M_B_CPU1_SB_DQS_DN<4>")
	)
	(segment
		(start 54.025038 -236.771942)
		(end 53.996844 -236.743748)
		(width 0.16002)
		(layer "In2.Cu")
		(net "M_B_CPU1_SB_DQS_DN<4>")
	)
	(segment
		(start 65.81013 -238.056166)
		(end 64.284098 -238.056166)
		(width 0.18288)
		(layer "In2.Cu")
		(net "M_B_CPU1_SB_DQS_DN<4>")
	)
	(segment
		(start 61.92012 -238.695992)
		(end 61.891926 -238.724186)
		(width 0.16002)
		(layer "In2.Cu")
		(net "M_B_CPU1_SB_DQS_DN<4>")
	)
	(segment
		(start 86.556596 -242.779804)
		(end 86.548214 -242.78463)
		(width 0.088646)
		(layer "In2.Cu")
		(net "M_B_CPU1_SB_DQS_DN<4>")
	)
	(arc
		(start 84.102194 -242.784376)
		(mid 84.021835 -242.749455)
		(end 83.93557 -242.734084)
		(width 0.088646)
		(layer "In2.Cu")
		(net "M_B_CPU1_SB_DQS_DN<4>")
	)
	(arc
		(start 89.74201 -242.78463)
		(mid 89.554812 -242.734487)
		(end 89.367614 -242.78463)
		(width 0.088646)
		(layer "In2.Cu")
		(net "M_B_CPU1_SB_DQS_DN<4>")
	)
	(arc
		(start 85.043264 -242.78463)
		(mid 84.856066 -242.734487)
		(end 84.668868 -242.78463)
		(width 0.088646)
		(layer "In2.Cu")
		(net "M_B_CPU1_SB_DQS_DN<4>")
	)
	(arc
		(start 87.488268 -242.78463)
		(mid 87.205312 -242.860499)
		(end 86.922356 -242.78463)
		(width 0.088646)
		(layer "In2.Cu")
		(net "M_B_CPU1_SB_DQS_DN<4>")
	)
	(arc
		(start 84.65693 -242.791488)
		(mid 84.378634 -242.860585)
		(end 84.102194 -242.784376)
		(width 0.088646)
		(layer "In2.Cu")
		(net "M_B_CPU1_SB_DQS_DN<4>")
	)
	(arc
		(start 85.597492 -242.790726)
		(mid 85.319568 -242.860296)
		(end 85.043264 -242.78463)
		(width 0.088646)
		(layer "In2.Cu")
		(net "M_B_CPU1_SB_DQS_DN<4>")
	)
	(arc
		(start 83.93557 -242.734084)
		(mid 83.924907 -242.733549)
		(end 83.914234 -242.733322)
		(width 0.088646)
		(layer "In2.Cu")
		(net "M_B_CPU1_SB_DQS_DN<4>")
	)
	(arc
		(start 86.53018 -242.795044)
		(mid 86.255022 -242.860537)
		(end 85.982556 -242.78463)
		(width 0.088646)
		(layer "In2.Cu")
		(net "M_B_CPU1_SB_DQS_DN<4>")
	)
	(arc
		(start 90.583766 -242.381278)
		(mid 90.491484 -242.614412)
		(end 90.307414 -242.78463)
		(width 0.088646)
		(layer "In2.Cu")
		(net "M_B_CPU1_SB_DQS_DN<4>")
	)
	(arc
		(start 89.352882 -242.793266)
		(mid 89.076441 -242.860432)
		(end 88.80221 -242.78463)
		(width 0.088646)
		(layer "In2.Cu")
		(net "M_B_CPU1_SB_DQS_DN<4>")
	)
	(arc
		(start 85.982556 -242.78463)
		(mid 85.803546 -242.734333)
		(end 85.622384 -242.776248)
		(width 0.088646)
		(layer "In2.Cu")
		(net "M_B_CPU1_SB_DQS_DN<4>")
	)
	(arc
		(start 88.413336 -242.793266)
		(mid 88.136895 -242.860432)
		(end 87.862664 -242.78463)
		(width 0.088646)
		(layer "In2.Cu")
		(net "M_B_CPU1_SB_DQS_DN<4>")
	)
	(arc
		(start 90.58656 -242.360196)
		(mid 90.585262 -242.37075)
		(end 90.583766 -242.381278)
		(width 0.088646)
		(layer "In2.Cu")
		(net "M_B_CPU1_SB_DQS_DN<4>")
	)
	(arc
		(start 86.922356 -242.78463)
		(mid 86.740105 -242.734519)
		(end 86.556596 -242.779804)
		(width 0.088646)
		(layer "In2.Cu")
		(net "M_B_CPU1_SB_DQS_DN<4>")
	)
	(arc
		(start 90.292682 -242.793266)
		(mid 90.016241 -242.860432)
		(end 89.74201 -242.78463)
		(width 0.088646)
		(layer "In2.Cu")
		(net "M_B_CPU1_SB_DQS_DN<4>")
	)
	(arc
		(start 88.80221 -242.78463)
		(mid 88.619959 -242.734519)
		(end 88.43645 -242.779804)
		(width 0.088646)
		(layer "In2.Cu")
		(net "M_B_CPU1_SB_DQS_DN<4>")
	)
	(arc
		(start 87.862664 -242.78463)
		(mid 87.675466 -242.734487)
		(end 87.488268 -242.78463)
		(width 0.088646)
		(layer "In2.Cu")
		(net "M_B_CPU1_SB_DQS_DN<4>")
	)
	(segment
		(start 43.616626 -200.2917)
		(end 41.30294 -200.2917)
		(width 0.1016)
		(layer "F.Cu")
		(net "M_B_CPU1_SB_DQS_DN<3>")
	)
	(segment
		(start 39.125398 -200.12787)
		(end 38.864286 -199.866758)
		(width 0.20066)
		(layer "F.Cu")
		(net "M_B_CPU1_SB_DQS_DN<3>")
	)
	(segment
		(start 45.312838 -199.866758)
		(end 45.051726 -200.12787)
		(width 0.20066)
		(layer "F.Cu")
		(net "M_B_CPU1_SB_DQS_DN<3>")
	)
	(segment
		(start 39.63924 -200.12787)
		(end 39.125398 -200.12787)
		(width 0.20066)
		(layer "F.Cu")
		(net "M_B_CPU1_SB_DQS_DN<3>")
	)
	(segment
		(start 44.645072 -200.12787)
		(end 44.219876 -200.553066)
		(width 0.20066)
		(layer "F.Cu")
		(net "M_B_CPU1_SB_DQS_DN<3>")
	)
	(segment
		(start 40.81526 -200.553066)
		(end 40.275256 -200.553066)
		(width 0.20066)
		(layer "F.Cu")
		(net "M_B_CPU1_SB_DQS_DN<3>")
	)
	(segment
		(start 44.033186 -200.553066)
		(end 43.77182 -200.2917)
		(width 0.20066)
		(layer "F.Cu")
		(net "M_B_CPU1_SB_DQS_DN<3>")
	)
	(segment
		(start 43.77182 -200.2917)
		(end 43.616626 -200.2917)
		(width 0.20066)
		(layer "F.Cu")
		(net "M_B_CPU1_SB_DQS_DN<3>")
	)
	(segment
		(start 41.087294 -200.281032)
		(end 40.81526 -200.553066)
		(width 0.20066)
		(layer "F.Cu")
		(net "M_B_CPU1_SB_DQS_DN<3>")
	)
	(segment
		(start 84.856066 -225.739198)
		(end 84.856066 -225.203258)
		(width 0.20066)
		(layer "F.Cu")
		(net "M_B_CPU1_SB_DQS_DN<3>")
	)
	(segment
		(start 41.29151 -200.281032)
		(end 41.087294 -200.281032)
		(width 0.20066)
		(layer "F.Cu")
		(net "M_B_CPU1_SB_DQS_DN<3>")
	)
	(segment
		(start 44.219876 -200.553066)
		(end 44.033186 -200.553066)
		(width 0.20066)
		(layer "F.Cu")
		(net "M_B_CPU1_SB_DQS_DN<3>")
	)
	(segment
		(start 46.964346 -199.866758)
		(end 45.859446 -199.866758)
		(width 0.20066)
		(layer "F.Cu")
		(net "M_B_CPU1_SB_DQS_DN<3>")
	)
	(segment
		(start 41.292272 -200.281032)
		(end 41.29151 -200.281032)
		(width 0.101854)
		(layer "F.Cu")
		(net "M_B_CPU1_SB_DQS_DN<3>")
	)
	(segment
		(start 40.275256 -200.553066)
		(end 39.63924 -200.12787)
		(width 0.20066)
		(layer "F.Cu")
		(net "M_B_CPU1_SB_DQS_DN<3>")
	)
	(segment
		(start 45.859446 -199.866758)
		(end 45.312838 -199.866758)
		(width 0.20066)
		(layer "F.Cu")
		(net "M_B_CPU1_SB_DQS_DN<3>")
	)
	(segment
		(start 45.051726 -200.12787)
		(end 44.645072 -200.12787)
		(width 0.20066)
		(layer "F.Cu")
		(net "M_B_CPU1_SB_DQS_DN<3>")
	)
	(segment
		(start 38.864286 -199.866758)
		(end 38.315646 -199.866758)
		(width 0.20066)
		(layer "F.Cu")
		(net "M_B_CPU1_SB_DQS_DN<3>")
	)
	(segment
		(start 41.30294 -200.2917)
		(end 41.292272 -200.281032)
		(width 0.101854)
		(layer "F.Cu")
		(net "M_B_CPU1_SB_DQS_DN<3>")
	)
	(segment
		(start 55.977028 -199.766174)
		(end 55.299356 -200.443846)
		(width 0.18288)
		(layer "In4.Cu")
		(net "M_B_CPU1_SB_DQS_DN<3>")
	)
	(segment
		(start 75.022202 -216.066116)
		(end 74.812398 -215.559386)
		(width 0.18288)
		(layer "In4.Cu")
		(net "M_B_CPU1_SB_DQS_DN<3>")
	)
	(segment
		(start 83.580732 -224.018856)
		(end 83.580732 -223.470724)
		(width 0.088646)
		(layer "In4.Cu")
		(net "M_B_CPU1_SB_DQS_DN<3>")
	)
	(segment
		(start 74.506836 -214.822278)
		(end 74.297032 -214.315548)
		(width 0.18288)
		(layer "In4.Cu")
		(net "M_B_CPU1_SB_DQS_DN<3>")
	)
	(segment
		(start 65.240408 -200.840848)
		(end 65.240408 -200.664826)
		(width 0.18288)
		(layer "In4.Cu")
		(net "M_B_CPU1_SB_DQS_DN<3>")
	)
	(segment
		(start 84.602574 -224.947226)
		(end 84.38134 -224.819464)
		(width 0.088646)
		(layer "In4.Cu")
		(net "M_B_CPU1_SB_DQS_DN<3>")
	)
	(segment
		(start 72.445626 -209.846926)
		(end 72.235822 -209.340196)
		(width 0.18288)
		(layer "In4.Cu")
		(net "M_B_CPU1_SB_DQS_DN<3>")
	)
	(segment
		(start 64.165734 -199.766174)
		(end 55.977028 -199.766174)
		(width 0.18288)
		(layer "In4.Cu")
		(net "M_B_CPU1_SB_DQS_DN<3>")
	)
	(segment
		(start 74.297032 -214.315548)
		(end 74.364342 -214.152988)
		(width 0.18288)
		(layer "In4.Cu")
		(net "M_B_CPU1_SB_DQS_DN<3>")
	)
	(segment
		(start 55.299356 -200.443846)
		(end 54.693312 -200.564496)
		(width 0.18288)
		(layer "In4.Cu")
		(net "M_B_CPU1_SB_DQS_DN<3>")
	)
	(segment
		(start 71.063104 -206.182722)
		(end 70.90029 -206.115412)
		(width 0.18288)
		(layer "In4.Cu")
		(net "M_B_CPU1_SB_DQS_DN<3>")
	)
	(segment
		(start 83.246468 -223.13646)
		(end 82.791554 -223.13646)
		(width 0.088646)
		(layer "In4.Cu")
		(net "M_B_CPU1_SB_DQS_DN<3>")
	)
	(segment
		(start 75.395074 -216.640664)
		(end 75.185016 -216.133426)
		(width 0.18288)
		(layer "In4.Cu")
		(net "M_B_CPU1_SB_DQS_DN<3>")
	)
	(segment
		(start 75.84313 -218.047062)
		(end 75.91044 -217.884502)
		(width 0.18288)
		(layer "In4.Cu")
		(net "M_B_CPU1_SB_DQS_DN<3>")
	)
	(segment
		(start 47.676562 -200.12533)
		(end 47.222918 -200.12533)
		(width 0.18288)
		(layer "In4.Cu")
		(net "M_B_CPU1_SB_DQS_DN<3>")
	)
	(segment
		(start 82.731864 -223.07677)
		(end 82.708496 -223.07677)
		(width 0.088646)
		(layer "In4.Cu")
		(net "M_B_CPU1_SB_DQS_DN<3>")
	)
	(segment
		(start 73.848976 -212.90915)
		(end 73.639172 -212.401912)
		(width 0.18288)
		(layer "In4.Cu")
		(net "M_B_CPU1_SB_DQS_DN<3>")
	)
	(segment
		(start 50.57648 -200.556622)
		(end 50.232056 -200.556622)
		(width 0.18288)
		(layer "In4.Cu")
		(net "M_B_CPU1_SB_DQS_DN<3>")
	)
	(segment
		(start 72.303132 -209.177636)
		(end 72.093328 -208.670398)
		(width 0.18288)
		(layer "In4.Cu")
		(net "M_B_CPU1_SB_DQS_DN<3>")
	)
	(segment
		(start 74.812398 -215.559386)
		(end 74.879708 -215.396826)
		(width 0.18288)
		(layer "In4.Cu")
		(net "M_B_CPU1_SB_DQS_DN<3>")
	)
	(segment
		(start 83.580732 -223.470724)
		(end 83.246468 -223.13646)
		(width 0.088646)
		(layer "In4.Cu")
		(net "M_B_CPU1_SB_DQS_DN<3>")
	)
	(segment
		(start 76.052934 -218.553792)
		(end 75.84313 -218.047062)
		(width 0.18288)
		(layer "In4.Cu")
		(net "M_B_CPU1_SB_DQS_DN<3>")
	)
	(segment
		(start 75.537568 -217.309954)
		(end 75.327764 -216.803224)
		(width 0.18288)
		(layer "In4.Cu")
		(net "M_B_CPU1_SB_DQS_DN<3>")
	)
	(segment
		(start 71.72071 -208.096358)
		(end 71.78802 -207.933798)
		(width 0.18288)
		(layer "In4.Cu")
		(net "M_B_CPU1_SB_DQS_DN<3>")
	)
	(segment
		(start 49.609502 -199.934068)
		(end 48.138588 -199.934068)
		(width 0.18288)
		(layer "In4.Cu")
		(net "M_B_CPU1_SB_DQS_DN<3>")
	)
	(segment
		(start 54.693312 -200.564496)
		(end 51.549808 -200.564496)
		(width 0.18288)
		(layer "In4.Cu")
		(net "M_B_CPU1_SB_DQS_DN<3>")
	)
	(segment
		(start 64.852296 -200.276714)
		(end 64.676274 -200.276714)
		(width 0.18288)
		(layer "In4.Cu")
		(net "M_B_CPU1_SB_DQS_DN<3>")
	)
	(segment
		(start 84.855812 -225.203258)
		(end 84.85124 -225.195384)
		(width 0.088646)
		(layer "In4.Cu")
		(net "M_B_CPU1_SB_DQS_DN<3>")
	)
	(segment
		(start 70.489572 -205.123796)
		(end 66.627756 -201.262234)
		(width 0.18288)
		(layer "In4.Cu")
		(net "M_B_CPU1_SB_DQS_DN<3>")
	)
	(segment
		(start 84.38134 -224.819464)
		(end 83.580732 -224.018856)
		(width 0.088646)
		(layer "In4.Cu")
		(net "M_B_CPU1_SB_DQS_DN<3>")
	)
	(segment
		(start 71.578216 -207.42656)
		(end 71.415402 -207.35925)
		(width 0.18288)
		(layer "In4.Cu")
		(net "M_B_CPU1_SB_DQS_DN<3>")
	)
	(segment
		(start 73.639172 -212.401912)
		(end 73.476104 -212.334602)
		(width 0.18288)
		(layer "In4.Cu")
		(net "M_B_CPU1_SB_DQS_DN<3>")
	)
	(segment
		(start 80.575658 -223.07677)
		(end 76.052934 -218.553792)
		(width 0.18288)
		(layer "In4.Cu")
		(net "M_B_CPU1_SB_DQS_DN<3>")
	)
	(segment
		(start 71.272908 -206.68996)
		(end 71.063104 -206.182722)
		(width 0.18288)
		(layer "In4.Cu")
		(net "M_B_CPU1_SB_DQS_DN<3>")
	)
	(segment
		(start 73.99147 -213.57844)
		(end 73.781666 -213.07171)
		(width 0.18288)
		(layer "In4.Cu")
		(net "M_B_CPU1_SB_DQS_DN<3>")
	)
	(segment
		(start 50.232056 -200.556622)
		(end 49.609502 -199.934068)
		(width 0.18288)
		(layer "In4.Cu")
		(net "M_B_CPU1_SB_DQS_DN<3>")
	)
	(segment
		(start 65.240408 -200.664826)
		(end 64.852296 -200.276714)
		(width 0.18288)
		(layer "In4.Cu")
		(net "M_B_CPU1_SB_DQS_DN<3>")
	)
	(segment
		(start 72.60844 -209.914236)
		(end 72.445626 -209.846926)
		(width 0.18288)
		(layer "In4.Cu")
		(net "M_B_CPU1_SB_DQS_DN<3>")
	)
	(segment
		(start 74.879708 -215.396826)
		(end 74.66965 -214.889588)
		(width 0.18288)
		(layer "In4.Cu")
		(net "M_B_CPU1_SB_DQS_DN<3>")
	)
	(segment
		(start 74.154284 -213.64575)
		(end 73.99147 -213.57844)
		(width 0.18288)
		(layer "In4.Cu")
		(net "M_B_CPU1_SB_DQS_DN<3>")
	)
	(segment
		(start 72.960738 -211.090764)
		(end 72.750934 -210.584034)
		(width 0.18288)
		(layer "In4.Cu")
		(net "M_B_CPU1_SB_DQS_DN<3>")
	)
	(segment
		(start 82.708496 -223.07677)
		(end 80.575658 -223.07677)
		(width 0.18288)
		(layer "In4.Cu")
		(net "M_B_CPU1_SB_DQS_DN<3>")
	)
	(segment
		(start 75.91044 -217.884502)
		(end 75.700382 -217.377264)
		(width 0.18288)
		(layer "In4.Cu")
		(net "M_B_CPU1_SB_DQS_DN<3>")
	)
	(segment
		(start 72.750934 -210.584034)
		(end 72.818244 -210.421474)
		(width 0.18288)
		(layer "In4.Cu")
		(net "M_B_CPU1_SB_DQS_DN<3>")
	)
	(segment
		(start 75.185016 -216.133426)
		(end 75.022202 -216.066116)
		(width 0.18288)
		(layer "In4.Cu")
		(net "M_B_CPU1_SB_DQS_DN<3>")
	)
	(segment
		(start 71.930514 -208.603088)
		(end 71.72071 -208.096358)
		(width 0.18288)
		(layer "In4.Cu")
		(net "M_B_CPU1_SB_DQS_DN<3>")
	)
	(segment
		(start 50.841402 -200.2917)
		(end 50.57648 -200.556622)
		(width 0.18288)
		(layer "In4.Cu")
		(net "M_B_CPU1_SB_DQS_DN<3>")
	)
	(segment
		(start 72.818244 -210.421474)
		(end 72.60844 -209.914236)
		(width 0.18288)
		(layer "In4.Cu")
		(net "M_B_CPU1_SB_DQS_DN<3>")
	)
	(segment
		(start 72.093328 -208.670398)
		(end 71.930514 -208.603088)
		(width 0.18288)
		(layer "In4.Cu")
		(net "M_B_CPU1_SB_DQS_DN<3>")
	)
	(segment
		(start 73.2663 -211.827872)
		(end 73.33361 -211.665312)
		(width 0.18288)
		(layer "In4.Cu")
		(net "M_B_CPU1_SB_DQS_DN<3>")
	)
	(segment
		(start 72.235822 -209.340196)
		(end 72.303132 -209.177636)
		(width 0.18288)
		(layer "In4.Cu")
		(net "M_B_CPU1_SB_DQS_DN<3>")
	)
	(segment
		(start 73.33361 -211.665312)
		(end 73.123806 -211.158074)
		(width 0.18288)
		(layer "In4.Cu")
		(net "M_B_CPU1_SB_DQS_DN<3>")
	)
	(segment
		(start 71.78802 -207.933798)
		(end 71.578216 -207.42656)
		(width 0.18288)
		(layer "In4.Cu")
		(net "M_B_CPU1_SB_DQS_DN<3>")
	)
	(segment
		(start 74.66965 -214.889588)
		(end 74.506836 -214.822278)
		(width 0.18288)
		(layer "In4.Cu")
		(net "M_B_CPU1_SB_DQS_DN<3>")
	)
	(segment
		(start 84.856066 -225.203258)
		(end 84.855812 -225.203258)
		(width 0.088646)
		(layer "In4.Cu")
		(net "M_B_CPU1_SB_DQS_DN<3>")
	)
	(segment
		(start 51.277012 -200.2917)
		(end 50.841402 -200.2917)
		(width 0.18288)
		(layer "In4.Cu")
		(net "M_B_CPU1_SB_DQS_DN<3>")
	)
	(segment
		(start 75.700382 -217.377264)
		(end 75.537568 -217.309954)
		(width 0.18288)
		(layer "In4.Cu")
		(net "M_B_CPU1_SB_DQS_DN<3>")
	)
	(segment
		(start 64.676274 -200.276714)
		(end 64.165734 -199.766174)
		(width 0.18288)
		(layer "In4.Cu")
		(net "M_B_CPU1_SB_DQS_DN<3>")
	)
	(segment
		(start 65.661794 -201.262234)
		(end 65.240408 -200.840848)
		(width 0.18288)
		(layer "In4.Cu")
		(net "M_B_CPU1_SB_DQS_DN<3>")
	)
	(segment
		(start 73.781666 -213.07171)
		(end 73.848976 -212.90915)
		(width 0.18288)
		(layer "In4.Cu")
		(net "M_B_CPU1_SB_DQS_DN<3>")
	)
	(segment
		(start 71.415402 -207.35925)
		(end 71.205598 -206.85252)
		(width 0.18288)
		(layer "In4.Cu")
		(net "M_B_CPU1_SB_DQS_DN<3>")
	)
	(segment
		(start 75.327764 -216.803224)
		(end 75.395074 -216.640664)
		(width 0.18288)
		(layer "In4.Cu")
		(net "M_B_CPU1_SB_DQS_DN<3>")
	)
	(segment
		(start 48.138588 -199.934068)
		(end 47.676562 -200.12533)
		(width 0.18288)
		(layer "In4.Cu")
		(net "M_B_CPU1_SB_DQS_DN<3>")
	)
	(segment
		(start 73.476104 -212.334602)
		(end 73.2663 -211.827872)
		(width 0.18288)
		(layer "In4.Cu")
		(net "M_B_CPU1_SB_DQS_DN<3>")
	)
	(segment
		(start 70.90029 -206.115412)
		(end 70.489572 -205.123796)
		(width 0.18288)
		(layer "In4.Cu")
		(net "M_B_CPU1_SB_DQS_DN<3>")
	)
	(segment
		(start 51.549808 -200.564496)
		(end 51.277012 -200.2917)
		(width 0.18288)
		(layer "In4.Cu")
		(net "M_B_CPU1_SB_DQS_DN<3>")
	)
	(segment
		(start 71.205598 -206.85252)
		(end 71.272908 -206.68996)
		(width 0.18288)
		(layer "In4.Cu")
		(net "M_B_CPU1_SB_DQS_DN<3>")
	)
	(segment
		(start 47.222918 -200.12533)
		(end 46.964346 -199.866758)
		(width 0.18288)
		(layer "In4.Cu")
		(net "M_B_CPU1_SB_DQS_DN<3>")
	)
	(segment
		(start 74.364342 -214.152988)
		(end 74.154284 -213.64575)
		(width 0.18288)
		(layer "In4.Cu")
		(net "M_B_CPU1_SB_DQS_DN<3>")
	)
	(segment
		(start 82.791554 -223.13646)
		(end 82.731864 -223.07677)
		(width 0.088646)
		(layer "In4.Cu")
		(net "M_B_CPU1_SB_DQS_DN<3>")
	)
	(segment
		(start 66.627756 -201.262234)
		(end 65.661794 -201.262234)
		(width 0.18288)
		(layer "In4.Cu")
		(net "M_B_CPU1_SB_DQS_DN<3>")
	)
	(segment
		(start 73.123806 -211.158074)
		(end 72.960738 -211.090764)
		(width 0.18288)
		(layer "In4.Cu")
		(net "M_B_CPU1_SB_DQS_DN<3>")
	)
	(arc
		(start 84.85124 -225.195384)
		(mid 84.743256 -225.054925)
		(end 84.602574 -224.947226)
		(width 0.088646)
		(layer "In4.Cu")
		(net "M_B_CPU1_SB_DQS_DN<3>")
	)
	(segment
		(start 45.051726 -209.477864)
		(end 44.645072 -209.477864)
		(width 0.20066)
		(layer "F.Cu")
		(net "M_B_CPU1_SB_DQS_DN<2>")
	)
	(segment
		(start 40.81526 -209.90306)
		(end 40.275256 -209.90306)
		(width 0.20066)
		(layer "F.Cu")
		(net "M_B_CPU1_SB_DQS_DN<2>")
	)
	(segment
		(start 40.275256 -209.90306)
		(end 39.63924 -209.477864)
		(width 0.20066)
		(layer "F.Cu")
		(net "M_B_CPU1_SB_DQS_DN<2>")
	)
	(segment
		(start 41.30294 -209.641694)
		(end 41.292272 -209.631026)
		(width 0.101854)
		(layer "F.Cu")
		(net "M_B_CPU1_SB_DQS_DN<2>")
	)
	(segment
		(start 45.859446 -209.216752)
		(end 45.312838 -209.216752)
		(width 0.20066)
		(layer "F.Cu")
		(net "M_B_CPU1_SB_DQS_DN<2>")
	)
	(segment
		(start 88.145366 -228.1809)
		(end 88.145366 -227.64496)
		(width 0.20066)
		(layer "F.Cu")
		(net "M_B_CPU1_SB_DQS_DN<2>")
	)
	(segment
		(start 39.125398 -209.477864)
		(end 38.864286 -209.216752)
		(width 0.20066)
		(layer "F.Cu")
		(net "M_B_CPU1_SB_DQS_DN<2>")
	)
	(segment
		(start 41.087294 -209.631026)
		(end 40.81526 -209.90306)
		(width 0.20066)
		(layer "F.Cu")
		(net "M_B_CPU1_SB_DQS_DN<2>")
	)
	(segment
		(start 43.616626 -209.641694)
		(end 41.30294 -209.641694)
		(width 0.1016)
		(layer "F.Cu")
		(net "M_B_CPU1_SB_DQS_DN<2>")
	)
	(segment
		(start 41.29151 -209.631026)
		(end 41.087294 -209.631026)
		(width 0.20066)
		(layer "F.Cu")
		(net "M_B_CPU1_SB_DQS_DN<2>")
	)
	(segment
		(start 43.77182 -209.641694)
		(end 43.616626 -209.641694)
		(width 0.20066)
		(layer "F.Cu")
		(net "M_B_CPU1_SB_DQS_DN<2>")
	)
	(segment
		(start 38.864286 -209.216752)
		(end 38.315646 -209.216752)
		(width 0.20066)
		(layer "F.Cu")
		(net "M_B_CPU1_SB_DQS_DN<2>")
	)
	(segment
		(start 41.292272 -209.631026)
		(end 41.29151 -209.631026)
		(width 0.101854)
		(layer "F.Cu")
		(net "M_B_CPU1_SB_DQS_DN<2>")
	)
	(segment
		(start 39.63924 -209.477864)
		(end 39.125398 -209.477864)
		(width 0.20066)
		(layer "F.Cu")
		(net "M_B_CPU1_SB_DQS_DN<2>")
	)
	(segment
		(start 44.219876 -209.90306)
		(end 44.033186 -209.90306)
		(width 0.20066)
		(layer "F.Cu")
		(net "M_B_CPU1_SB_DQS_DN<2>")
	)
	(segment
		(start 44.645072 -209.477864)
		(end 44.219876 -209.90306)
		(width 0.20066)
		(layer "F.Cu")
		(net "M_B_CPU1_SB_DQS_DN<2>")
	)
	(segment
		(start 46.964346 -209.216752)
		(end 45.859446 -209.216752)
		(width 0.20066)
		(layer "F.Cu")
		(net "M_B_CPU1_SB_DQS_DN<2>")
	)
	(segment
		(start 45.312838 -209.216752)
		(end 45.051726 -209.477864)
		(width 0.20066)
		(layer "F.Cu")
		(net "M_B_CPU1_SB_DQS_DN<2>")
	)
	(segment
		(start 44.033186 -209.90306)
		(end 43.77182 -209.641694)
		(width 0.20066)
		(layer "F.Cu")
		(net "M_B_CPU1_SB_DQS_DN<2>")
	)
	(segment
		(start 75.74026 -214.788496)
		(end 75.355704 -214.40394)
		(width 0.18288)
		(layer "In2.Cu")
		(net "M_B_CPU1_SB_DQS_DN<2>")
	)
	(segment
		(start 52.433474 -210.210908)
		(end 52.40528 -210.182714)
		(width 0.16002)
		(layer "In2.Cu")
		(net "M_B_CPU1_SB_DQS_DN<2>")
	)
	(segment
		(start 59.973972 -208.653126)
		(end 59.77382 -208.853278)
		(width 0.16002)
		(layer "In2.Cu")
		(net "M_B_CPU1_SB_DQS_DN<2>")
	)
	(segment
		(start 64.293242 -209.576924)
		(end 64.276986 -209.576924)
		(width 0.16002)
		(layer "In2.Cu")
		(net "M_B_CPU1_SB_DQS_DN<2>")
	)
	(segment
		(start 77.245464 -216.2937)
		(end 77.069442 -216.2937)
		(width 0.18288)
		(layer "In2.Cu")
		(net "M_B_CPU1_SB_DQS_DN<2>")
	)
	(segment
		(start 55.527956 -209.05597)
		(end 54.401212 -210.182714)
		(width 0.18288)
		(layer "In2.Cu")
		(net "M_B_CPU1_SB_DQS_DN<2>")
	)
	(segment
		(start 65.772792 -209.605118)
		(end 65.680336 -209.697574)
		(width 0.18288)
		(layer "In2.Cu")
		(net "M_B_CPU1_SB_DQS_DN<2>")
	)
	(segment
		(start 66.016886 -209.37728)
		(end 65.817242 -209.576924)
		(width 0.16002)
		(layer "In2.Cu")
		(net "M_B_CPU1_SB_DQS_DN<2>")
	)
	(segment
		(start 73.289922 -212.51418)
		(end 72.90562 -212.129878)
		(width 0.18288)
		(layer "In2.Cu")
		(net "M_B_CPU1_SB_DQS_DN<2>")
	)
	(segment
		(start 56.505348 -209.33283)
		(end 56.228488 -209.05597)
		(width 0.18288)
		(layer "In2.Cu")
		(net "M_B_CPU1_SB_DQS_DN<2>")
	)
	(segment
		(start 88.145366 -227.64496)
		(end 88.118442 -227.582984)
		(width 0.088646)
		(layer "In2.Cu")
		(net "M_B_CPU1_SB_DQS_DN<2>")
	)
	(segment
		(start 72.90562 -211.953856)
		(end 72.521064 -211.5693)
		(width 0.18288)
		(layer "In2.Cu")
		(net "M_B_CPU1_SB_DQS_DN<2>")
	)
	(segment
		(start 64.276986 -209.576924)
		(end 64.077342 -209.37728)
		(width 0.16002)
		(layer "In2.Cu")
		(net "M_B_CPU1_SB_DQS_DN<2>")
	)
	(segment
		(start 76.68514 -215.909398)
		(end 76.68514 -215.733376)
		(width 0.18288)
		(layer "In2.Cu")
		(net "M_B_CPU1_SB_DQS_DN<2>")
	)
	(segment
		(start 77.63002 -216.854278)
		(end 77.63002 -216.678256)
		(width 0.18288)
		(layer "In2.Cu")
		(net "M_B_CPU1_SB_DQS_DN<2>")
	)
	(segment
		(start 70.631304 -209.67954)
		(end 70.455282 -209.67954)
		(width 0.18288)
		(layer "In2.Cu")
		(net "M_B_CPU1_SB_DQS_DN<2>")
	)
	(segment
		(start 86.830916 -226.025964)
		(end 86.830916 -225.998786)
		(width 0.088646)
		(layer "In2.Cu")
		(net "M_B_CPU1_SB_DQS_DN<2>")
	)
	(segment
		(start 64.077342 -209.37728)
		(end 64.077342 -209.361024)
		(width 0.16002)
		(layer "In2.Cu")
		(net "M_B_CPU1_SB_DQS_DN<2>")
	)
	(segment
		(start 54.173374 -210.426808)
		(end 54.157118 -210.426808)
		(width 0.16002)
		(layer "In2.Cu")
		(net "M_B_CPU1_SB_DQS_DN<2>")
	)
	(segment
		(start 52.131468 -209.908902)
		(end 51.513994 -209.908902)
		(width 0.18288)
		(layer "In2.Cu")
		(net "M_B_CPU1_SB_DQS_DN<2>")
	)
	(segment
		(start 84.127848 -223.281748)
		(end 84.068158 -223.222058)
		(width 0.088646)
		(layer "In2.Cu")
		(net "M_B_CPU1_SB_DQS_DN<2>")
	)
	(segment
		(start 54.036468 -210.547458)
		(end 52.770024 -210.547458)
		(width 0.18288)
		(layer "In2.Cu")
		(net "M_B_CPU1_SB_DQS_DN<2>")
	)
	(segment
		(start 58.228992 -209.605118)
		(end 58.136536 -209.697574)
		(width 0.18288)
		(layer "In2.Cu")
		(net "M_B_CPU1_SB_DQS_DN<2>")
	)
	(segment
		(start 58.473086 -209.361024)
		(end 58.473086 -209.37728)
		(width 0.16002)
		(layer "In2.Cu")
		(net "M_B_CPU1_SB_DQS_DN<2>")
	)
	(segment
		(start 52.770024 -210.547458)
		(end 52.677568 -210.455002)
		(width 0.18288)
		(layer "In2.Cu")
		(net "M_B_CPU1_SB_DQS_DN<2>")
	)
	(segment
		(start 75.179682 -214.40394)
		(end 74.79538 -214.019638)
		(width 0.18288)
		(layer "In2.Cu")
		(net "M_B_CPU1_SB_DQS_DN<2>")
	)
	(segment
		(start 76.124562 -215.34882)
		(end 75.74026 -214.964518)
		(width 0.18288)
		(layer "In2.Cu")
		(net "M_B_CPU1_SB_DQS_DN<2>")
	)
	(segment
		(start 54.128924 -210.455002)
		(end 54.036468 -210.547458)
		(width 0.18288)
		(layer "In2.Cu")
		(net "M_B_CPU1_SB_DQS_DN<2>")
	)
	(segment
		(start 59.758072 -208.853278)
		(end 59.729878 -208.881472)
		(width 0.16002)
		(layer "In2.Cu")
		(net "M_B_CPU1_SB_DQS_DN<2>")
	)
	(segment
		(start 71.01586 -210.064096)
		(end 70.631304 -209.67954)
		(width 0.18288)
		(layer "In2.Cu")
		(net "M_B_CPU1_SB_DQS_DN<2>")
	)
	(segment
		(start 84.34959 -223.281748)
		(end 84.127848 -223.281748)
		(width 0.088646)
		(layer "In2.Cu")
		(net "M_B_CPU1_SB_DQS_DN<2>")
	)
	(segment
		(start 58.273442 -209.576924)
		(end 58.257186 -209.576924)
		(width 0.16002)
		(layer "In2.Cu")
		(net "M_B_CPU1_SB_DQS_DN<2>")
	)
	(segment
		(start 47.234348 -209.486754)
		(end 46.964346 -209.216752)
		(width 0.18288)
		(layer "In2.Cu")
		(net "M_B_CPU1_SB_DQS_DN<2>")
	)
	(segment
		(start 87.030306 -226.348798)
		(end 87.018114 -226.341686)
		(width 0.088646)
		(layer "In2.Cu")
		(net "M_B_CPU1_SB_DQS_DN<2>")
	)
	(segment
		(start 49.313846 -209.716624)
		(end 49.114202 -209.51698)
		(width 0.16002)
		(layer "In2.Cu")
		(net "M_B_CPU1_SB_DQS_DN<2>")
	)
	(segment
		(start 86.077806 -224.713292)
		(end 86.075266 -224.711768)
		(width 0.088646)
		(layer "In2.Cu")
		(net "M_B_CPU1_SB_DQS_DN<2>")
	)
	(segment
		(start 61.92012 -208.637378)
		(end 61.891926 -208.609184)
		(width 0.16002)
		(layer "In2.Cu")
		(net "M_B_CPU1_SB_DQS_DN<2>")
	)
	(segment
		(start 58.136536 -209.697574)
		(end 56.870092 -209.697574)
		(width 0.18288)
		(layer "In2.Cu")
		(net "M_B_CPU1_SB_DQS_DN<2>")
	)
	(segment
		(start 77.63002 -216.678256)
		(end 77.245464 -216.2937)
		(width 0.18288)
		(layer "In2.Cu")
		(net "M_B_CPU1_SB_DQS_DN<2>")
	)
	(segment
		(start 74.410824 -213.45906)
		(end 74.234802 -213.45906)
		(width 0.18288)
		(layer "In2.Cu")
		(net "M_B_CPU1_SB_DQS_DN<2>")
	)
	(segment
		(start 75.74026 -214.964518)
		(end 75.74026 -214.788496)
		(width 0.18288)
		(layer "In2.Cu")
		(net "M_B_CPU1_SB_DQS_DN<2>")
	)
	(segment
		(start 56.749442 -209.576924)
		(end 56.733186 -209.576924)
		(width 0.16002)
		(layer "In2.Cu")
		(net "M_B_CPU1_SB_DQS_DN<2>")
	)
	(segment
		(start 52.677568 -210.455002)
		(end 52.649374 -210.426808)
		(width 0.16002)
		(layer "In2.Cu")
		(net "M_B_CPU1_SB_DQS_DN<2>")
	)
	(segment
		(start 50.587402 -209.924396)
		(end 49.537874 -209.924396)
		(width 0.18288)
		(layer "In2.Cu")
		(net "M_B_CPU1_SB_DQS_DN<2>")
	)
	(segment
		(start 78.636114 -217.68435)
		(end 78.251558 -217.299794)
		(width 0.18288)
		(layer "In2.Cu")
		(net "M_B_CPU1_SB_DQS_DN<2>")
	)
	(segment
		(start 58.80862 -209.02549)
		(end 58.50128 -209.33283)
		(width 0.18288)
		(layer "In2.Cu")
		(net "M_B_CPU1_SB_DQS_DN<2>")
	)
	(segment
		(start 56.733186 -209.576924)
		(end 56.533542 -209.37728)
		(width 0.16002)
		(layer "In2.Cu")
		(net "M_B_CPU1_SB_DQS_DN<2>")
	)
	(segment
		(start 85.608668 -223.899984)
		(end 85.599778 -223.894904)
		(width 0.088646)
		(layer "In2.Cu")
		(net "M_B_CPU1_SB_DQS_DN<2>")
	)
	(segment
		(start 49.537874 -209.924396)
		(end 49.358296 -209.744818)
		(width 0.18288)
		(layer "In2.Cu")
		(net "M_B_CPU1_SB_DQS_DN<2>")
	)
	(segment
		(start 76.300584 -215.34882)
		(end 76.124562 -215.34882)
		(width 0.18288)
		(layer "In2.Cu")
		(net "M_B_CPU1_SB_DQS_DN<2>")
	)
	(segment
		(start 48.844708 -209.23123)
		(end 48.20031 -209.23123)
		(width 0.18288)
		(layer "In2.Cu")
		(net "M_B_CPU1_SB_DQS_DN<2>")
	)
	(segment
		(start 52.633118 -210.426808)
		(end 52.433474 -210.227164)
		(width 0.16002)
		(layer "In2.Cu")
		(net "M_B_CPU1_SB_DQS_DN<2>")
	)
	(segment
		(start 66.04508 -209.33283)
		(end 66.016886 -209.361024)
		(width 0.16002)
		(layer "In2.Cu")
		(net "M_B_CPU1_SB_DQS_DN<2>")
	)
	(segment
		(start 83.9978 -223.222058)
		(end 78.636114 -217.860372)
		(width 0.18288)
		(layer "In2.Cu")
		(net "M_B_CPU1_SB_DQS_DN<2>")
	)
	(segment
		(start 65.817242 -209.576924)
		(end 65.800986 -209.576924)
		(width 0.16002)
		(layer "In2.Cu")
		(net "M_B_CPU1_SB_DQS_DN<2>")
	)
	(segment
		(start 73.8505 -212.898736)
		(end 73.465944 -212.51418)
		(width 0.18288)
		(layer "In2.Cu")
		(net "M_B_CPU1_SB_DQS_DN<2>")
	)
	(segment
		(start 84.456016 -223.175322)
		(end 84.34959 -223.281748)
		(width 0.088646)
		(layer "In2.Cu")
		(net "M_B_CPU1_SB_DQS_DN<2>")
	)
	(segment
		(start 67.68211 -209.170778)
		(end 67.55765 -209.295238)
		(width 0.18288)
		(layer "In2.Cu")
		(net "M_B_CPU1_SB_DQS_DN<2>")
	)
	(segment
		(start 59.973972 -208.637378)
		(end 59.973972 -208.653126)
		(width 0.16002)
		(layer "In2.Cu")
		(net "M_B_CPU1_SB_DQS_DN<2>")
	)
	(segment
		(start 70.07098 -209.295238)
		(end 69.70141 -209.295238)
		(width 0.18288)
		(layer "In2.Cu")
		(net "M_B_CPU1_SB_DQS_DN<2>")
	)
	(segment
		(start 49.086008 -209.47253)
		(end 48.844708 -209.23123)
		(width 0.18288)
		(layer "In2.Cu")
		(net "M_B_CPU1_SB_DQS_DN<2>")
	)
	(segment
		(start 64.077342 -209.361024)
		(end 64.049148 -209.33283)
		(width 0.16002)
		(layer "In2.Cu")
		(net "M_B_CPU1_SB_DQS_DN<2>")
	)
	(segment
		(start 71.01586 -210.240118)
		(end 71.01586 -210.064096)
		(width 0.18288)
		(layer "In2.Cu")
		(net "M_B_CPU1_SB_DQS_DN<2>")
	)
	(segment
		(start 78.075536 -217.299794)
		(end 77.63002 -216.854278)
		(width 0.18288)
		(layer "In2.Cu")
		(net "M_B_CPU1_SB_DQS_DN<2>")
	)
	(segment
		(start 72.345042 -211.5693)
		(end 71.96074 -211.184998)
		(width 0.18288)
		(layer "In2.Cu")
		(net "M_B_CPU1_SB_DQS_DN<2>")
	)
	(segment
		(start 52.433474 -210.227164)
		(end 52.433474 -210.210908)
		(width 0.16002)
		(layer "In2.Cu")
		(net "M_B_CPU1_SB_DQS_DN<2>")
	)
	(segment
		(start 86.078568 -224.7138)
		(end 86.077806 -224.713292)
		(width 0.088646)
		(layer "In2.Cu")
		(net "M_B_CPU1_SB_DQS_DN<2>")
	)
	(segment
		(start 74.234802 -213.45906)
		(end 73.8505 -213.074758)
		(width 0.18288)
		(layer "In2.Cu")
		(net "M_B_CPU1_SB_DQS_DN<2>")
	)
	(segment
		(start 73.465944 -212.51418)
		(end 73.289922 -212.51418)
		(width 0.18288)
		(layer "In2.Cu")
		(net "M_B_CPU1_SB_DQS_DN<2>")
	)
	(segment
		(start 62.120272 -208.853278)
		(end 61.92012 -208.653126)
		(width 0.16002)
		(layer "In2.Cu")
		(net "M_B_CPU1_SB_DQS_DN<2>")
	)
	(segment
		(start 62.13602 -208.853278)
		(end 62.120272 -208.853278)
		(width 0.16002)
		(layer "In2.Cu")
		(net "M_B_CPU1_SB_DQS_DN<2>")
	)
	(segment
		(start 61.708792 -208.42605)
		(end 60.1853 -208.42605)
		(width 0.18288)
		(layer "In2.Cu")
		(net "M_B_CPU1_SB_DQS_DN<2>")
	)
	(segment
		(start 56.533542 -209.37728)
		(end 56.533542 -209.361024)
		(width 0.16002)
		(layer "In2.Cu")
		(net "M_B_CPU1_SB_DQS_DN<2>")
	)
	(segment
		(start 85.421216 -223.575626)
		(end 85.421216 -223.561402)
		(width 0.088646)
		(layer "In2.Cu")
		(net "M_B_CPU1_SB_DQS_DN<2>")
	)
	(segment
		(start 67.55765 -209.295238)
		(end 66.934588 -209.295238)
		(width 0.18288)
		(layer "In2.Cu")
		(net "M_B_CPU1_SB_DQS_DN<2>")
	)
	(segment
		(start 56.870092 -209.697574)
		(end 56.777636 -209.605118)
		(width 0.18288)
		(layer "In2.Cu")
		(net "M_B_CPU1_SB_DQS_DN<2>")
	)
	(segment
		(start 49.330102 -209.716624)
		(end 49.313846 -209.716624)
		(width 0.16002)
		(layer "In2.Cu")
		(net "M_B_CPU1_SB_DQS_DN<2>")
	)
	(segment
		(start 74.79538 -214.019638)
		(end 74.79538 -213.843616)
		(width 0.18288)
		(layer "In2.Cu")
		(net "M_B_CPU1_SB_DQS_DN<2>")
	)
	(segment
		(start 71.96074 -211.008976)
		(end 71.576184 -210.62442)
		(width 0.18288)
		(layer "In2.Cu")
		(net "M_B_CPU1_SB_DQS_DN<2>")
	)
	(segment
		(start 56.228488 -209.05597)
		(end 55.527956 -209.05597)
		(width 0.18288)
		(layer "In2.Cu")
		(net "M_B_CPU1_SB_DQS_DN<2>")
	)
	(segment
		(start 68.35521 -209.295238)
		(end 68.23075 -209.170778)
		(width 0.18288)
		(layer "In2.Cu")
		(net "M_B_CPU1_SB_DQS_DN<2>")
	)
	(segment
		(start 47.58309 -209.486754)
		(end 47.234348 -209.486754)
		(width 0.18288)
		(layer "In2.Cu")
		(net "M_B_CPU1_SB_DQS_DN<2>")
	)
	(segment
		(start 54.373018 -210.210908)
		(end 54.373018 -210.227164)
		(width 0.16002)
		(layer "In2.Cu")
		(net "M_B_CPU1_SB_DQS_DN<2>")
	)
	(segment
		(start 48.20031 -209.23123)
		(end 47.58309 -209.486754)
		(width 0.18288)
		(layer "In2.Cu")
		(net "M_B_CPU1_SB_DQS_DN<2>")
	)
	(segment
		(start 56.533542 -209.361024)
		(end 56.505348 -209.33283)
		(width 0.16002)
		(layer "In2.Cu")
		(net "M_B_CPU1_SB_DQS_DN<2>")
	)
	(segment
		(start 69.70141 -209.295238)
		(end 69.57695 -209.170778)
		(width 0.18288)
		(layer "In2.Cu")
		(net "M_B_CPU1_SB_DQS_DN<2>")
	)
	(segment
		(start 65.680336 -209.697574)
		(end 64.413892 -209.697574)
		(width 0.18288)
		(layer "In2.Cu")
		(net "M_B_CPU1_SB_DQS_DN<2>")
	)
	(segment
		(start 84.068158 -223.222058)
		(end 83.9978 -223.222058)
		(width 0.18288)
		(layer "In2.Cu")
		(net "M_B_CPU1_SB_DQS_DN<2>")
	)
	(segment
		(start 68.23075 -209.170778)
		(end 67.68211 -209.170778)
		(width 0.18288)
		(layer "In2.Cu")
		(net "M_B_CPU1_SB_DQS_DN<2>")
	)
	(segment
		(start 86.361016 -225.203258)
		(end 86.361016 -225.193352)
		(width 0.088646)
		(layer "In2.Cu")
		(net "M_B_CPU1_SB_DQS_DN<2>")
	)
	(segment
		(start 54.373018 -210.227164)
		(end 54.173374 -210.426808)
		(width 0.16002)
		(layer "In2.Cu")
		(net "M_B_CPU1_SB_DQS_DN<2>")
	)
	(segment
		(start 64.413892 -209.697574)
		(end 64.321436 -209.605118)
		(width 0.18288)
		(layer "In2.Cu")
		(net "M_B_CPU1_SB_DQS_DN<2>")
	)
	(segment
		(start 60.002166 -208.609184)
		(end 59.973972 -208.637378)
		(width 0.16002)
		(layer "In2.Cu")
		(net "M_B_CPU1_SB_DQS_DN<2>")
	)
	(segment
		(start 68.90385 -209.295238)
		(end 68.35521 -209.295238)
		(width 0.18288)
		(layer "In2.Cu")
		(net "M_B_CPU1_SB_DQS_DN<2>")
	)
	(segment
		(start 65.800986 -209.576924)
		(end 65.772792 -209.605118)
		(width 0.16002)
		(layer "In2.Cu")
		(net "M_B_CPU1_SB_DQS_DN<2>")
	)
	(segment
		(start 72.90562 -212.129878)
		(end 72.90562 -211.953856)
		(width 0.18288)
		(layer "In2.Cu")
		(net "M_B_CPU1_SB_DQS_DN<2>")
	)
	(segment
		(start 49.114202 -209.500724)
		(end 49.086008 -209.47253)
		(width 0.16002)
		(layer "In2.Cu")
		(net "M_B_CPU1_SB_DQS_DN<2>")
	)
	(segment
		(start 51.246786 -209.641694)
		(end 50.870104 -209.641694)
		(width 0.18288)
		(layer "In2.Cu")
		(net "M_B_CPU1_SB_DQS_DN<2>")
	)
	(segment
		(start 72.521064 -211.5693)
		(end 72.345042 -211.5693)
		(width 0.18288)
		(layer "In2.Cu")
		(net "M_B_CPU1_SB_DQS_DN<2>")
	)
	(segment
		(start 73.8505 -213.074758)
		(end 73.8505 -212.898736)
		(width 0.18288)
		(layer "In2.Cu")
		(net "M_B_CPU1_SB_DQS_DN<2>")
	)
	(segment
		(start 58.50128 -209.33283)
		(end 58.473086 -209.361024)
		(width 0.16002)
		(layer "In2.Cu")
		(net "M_B_CPU1_SB_DQS_DN<2>")
	)
	(segment
		(start 74.79538 -213.843616)
		(end 74.410824 -213.45906)
		(width 0.18288)
		(layer "In2.Cu")
		(net "M_B_CPU1_SB_DQS_DN<2>")
	)
	(segment
		(start 85.614764 -223.90354)
		(end 85.608668 -223.899984)
		(width 0.088646)
		(layer "In2.Cu")
		(net "M_B_CPU1_SB_DQS_DN<2>")
	)
	(segment
		(start 60.1853 -208.42605)
		(end 60.002166 -208.609184)
		(width 0.18288)
		(layer "In2.Cu")
		(net "M_B_CPU1_SB_DQS_DN<2>")
	)
	(segment
		(start 54.401212 -210.182714)
		(end 54.373018 -210.210908)
		(width 0.16002)
		(layer "In2.Cu")
		(net "M_B_CPU1_SB_DQS_DN<2>")
	)
	(segment
		(start 70.455282 -209.67954)
		(end 70.07098 -209.295238)
		(width 0.18288)
		(layer "In2.Cu")
		(net "M_B_CPU1_SB_DQS_DN<2>")
	)
	(segment
		(start 52.649374 -210.426808)
		(end 52.633118 -210.426808)
		(width 0.16002)
		(layer "In2.Cu")
		(net "M_B_CPU1_SB_DQS_DN<2>")
	)
	(segment
		(start 49.114202 -209.51698)
		(end 49.114202 -209.500724)
		(width 0.16002)
		(layer "In2.Cu")
		(net "M_B_CPU1_SB_DQS_DN<2>")
	)
	(segment
		(start 63.768986 -209.052668)
		(end 62.33541 -209.052668)
		(width 0.18288)
		(layer "In2.Cu")
		(net "M_B_CPU1_SB_DQS_DN<2>")
	)
	(segment
		(start 61.92012 -208.653126)
		(end 61.92012 -208.637378)
		(width 0.16002)
		(layer "In2.Cu")
		(net "M_B_CPU1_SB_DQS_DN<2>")
	)
	(segment
		(start 59.58586 -209.02549)
		(end 58.80862 -209.02549)
		(width 0.18288)
		(layer "In2.Cu")
		(net "M_B_CPU1_SB_DQS_DN<2>")
	)
	(segment
		(start 66.934588 -209.295238)
		(end 66.775584 -209.136234)
		(width 0.18288)
		(layer "In2.Cu")
		(net "M_B_CPU1_SB_DQS_DN<2>")
	)
	(segment
		(start 51.513994 -209.908902)
		(end 51.246786 -209.641694)
		(width 0.18288)
		(layer "In2.Cu")
		(net "M_B_CPU1_SB_DQS_DN<2>")
	)
	(segment
		(start 71.400162 -210.62442)
		(end 71.01586 -210.240118)
		(width 0.18288)
		(layer "In2.Cu")
		(net "M_B_CPU1_SB_DQS_DN<2>")
	)
	(segment
		(start 62.33541 -209.052668)
		(end 62.164214 -208.881472)
		(width 0.18288)
		(layer "In2.Cu")
		(net "M_B_CPU1_SB_DQS_DN<2>")
	)
	(segment
		(start 69.57695 -209.170778)
		(end 69.02831 -209.170778)
		(width 0.18288)
		(layer "In2.Cu")
		(net "M_B_CPU1_SB_DQS_DN<2>")
	)
	(segment
		(start 77.069442 -216.2937)
		(end 76.68514 -215.909398)
		(width 0.18288)
		(layer "In2.Cu")
		(net "M_B_CPU1_SB_DQS_DN<2>")
	)
	(segment
		(start 71.96074 -211.184998)
		(end 71.96074 -211.008976)
		(width 0.18288)
		(layer "In2.Cu")
		(net "M_B_CPU1_SB_DQS_DN<2>")
	)
	(segment
		(start 86.548468 -225.527616)
		(end 86.539578 -225.522536)
		(width 0.088646)
		(layer "In2.Cu")
		(net "M_B_CPU1_SB_DQS_DN<2>")
	)
	(segment
		(start 59.77382 -208.853278)
		(end 59.758072 -208.853278)
		(width 0.16002)
		(layer "In2.Cu")
		(net "M_B_CPU1_SB_DQS_DN<2>")
	)
	(segment
		(start 85.138514 -223.085914)
		(end 85.123782 -223.077278)
		(width 0.088646)
		(layer "In2.Cu")
		(net "M_B_CPU1_SB_DQS_DN<2>")
	)
	(segment
		(start 64.321436 -209.605118)
		(end 64.293242 -209.576924)
		(width 0.16002)
		(layer "In2.Cu")
		(net "M_B_CPU1_SB_DQS_DN<2>")
	)
	(segment
		(start 52.40528 -210.182714)
		(end 52.131468 -209.908902)
		(width 0.18288)
		(layer "In2.Cu")
		(net "M_B_CPU1_SB_DQS_DN<2>")
	)
	(segment
		(start 62.164214 -208.881472)
		(end 62.13602 -208.853278)
		(width 0.16002)
		(layer "In2.Cu")
		(net "M_B_CPU1_SB_DQS_DN<2>")
	)
	(segment
		(start 58.473086 -209.37728)
		(end 58.273442 -209.576924)
		(width 0.16002)
		(layer "In2.Cu")
		(net "M_B_CPU1_SB_DQS_DN<2>")
	)
	(segment
		(start 87.957406 -227.42652)
		(end 87.488014 -227.155502)
		(width 0.088646)
		(layer "In2.Cu")
		(net "M_B_CPU1_SB_DQS_DN<2>")
	)
	(segment
		(start 54.157118 -210.426808)
		(end 54.128924 -210.455002)
		(width 0.16002)
		(layer "In2.Cu")
		(net "M_B_CPU1_SB_DQS_DN<2>")
	)
	(segment
		(start 49.358296 -209.744818)
		(end 49.330102 -209.716624)
		(width 0.16002)
		(layer "In2.Cu")
		(net "M_B_CPU1_SB_DQS_DN<2>")
	)
	(segment
		(start 58.257186 -209.576924)
		(end 58.228992 -209.605118)
		(width 0.16002)
		(layer "In2.Cu")
		(net "M_B_CPU1_SB_DQS_DN<2>")
	)
	(segment
		(start 59.729878 -208.881472)
		(end 59.58586 -209.02549)
		(width 0.18288)
		(layer "In2.Cu")
		(net "M_B_CPU1_SB_DQS_DN<2>")
	)
	(segment
		(start 66.241676 -209.136234)
		(end 66.04508 -209.33283)
		(width 0.18288)
		(layer "In2.Cu")
		(net "M_B_CPU1_SB_DQS_DN<2>")
	)
	(segment
		(start 61.891926 -208.609184)
		(end 61.708792 -208.42605)
		(width 0.18288)
		(layer "In2.Cu")
		(net "M_B_CPU1_SB_DQS_DN<2>")
	)
	(segment
		(start 78.636114 -217.860372)
		(end 78.636114 -217.68435)
		(width 0.18288)
		(layer "In2.Cu")
		(net "M_B_CPU1_SB_DQS_DN<2>")
	)
	(segment
		(start 78.251558 -217.299794)
		(end 78.075536 -217.299794)
		(width 0.18288)
		(layer "In2.Cu")
		(net "M_B_CPU1_SB_DQS_DN<2>")
	)
	(segment
		(start 71.576184 -210.62442)
		(end 71.400162 -210.62442)
		(width 0.18288)
		(layer "In2.Cu")
		(net "M_B_CPU1_SB_DQS_DN<2>")
	)
	(segment
		(start 50.870104 -209.641694)
		(end 50.587402 -209.924396)
		(width 0.18288)
		(layer "In2.Cu")
		(net "M_B_CPU1_SB_DQS_DN<2>")
	)
	(segment
		(start 64.049148 -209.33283)
		(end 63.768986 -209.052668)
		(width 0.18288)
		(layer "In2.Cu")
		(net "M_B_CPU1_SB_DQS_DN<2>")
	)
	(segment
		(start 88.118442 -227.582984)
		(end 87.957406 -227.42652)
		(width 0.088646)
		(layer "In2.Cu")
		(net "M_B_CPU1_SB_DQS_DN<2>")
	)
	(segment
		(start 56.777636 -209.605118)
		(end 56.749442 -209.576924)
		(width 0.16002)
		(layer "In2.Cu")
		(net "M_B_CPU1_SB_DQS_DN<2>")
	)
	(segment
		(start 66.016886 -209.361024)
		(end 66.016886 -209.37728)
		(width 0.16002)
		(layer "In2.Cu")
		(net "M_B_CPU1_SB_DQS_DN<2>")
	)
	(segment
		(start 69.02831 -209.170778)
		(end 68.90385 -209.295238)
		(width 0.18288)
		(layer "In2.Cu")
		(net "M_B_CPU1_SB_DQS_DN<2>")
	)
	(segment
		(start 86.075266 -224.711768)
		(end 86.069678 -224.70872)
		(width 0.088646)
		(layer "In2.Cu")
		(net "M_B_CPU1_SB_DQS_DN<2>")
	)
	(segment
		(start 75.355704 -214.40394)
		(end 75.179682 -214.40394)
		(width 0.18288)
		(layer "In2.Cu")
		(net "M_B_CPU1_SB_DQS_DN<2>")
	)
	(segment
		(start 76.68514 -215.733376)
		(end 76.300584 -215.34882)
		(width 0.18288)
		(layer "In2.Cu")
		(net "M_B_CPU1_SB_DQS_DN<2>")
	)
	(segment
		(start 66.775584 -209.136234)
		(end 66.241676 -209.136234)
		(width 0.18288)
		(layer "In2.Cu")
		(net "M_B_CPU1_SB_DQS_DN<2>")
	)
	(arc
		(start 86.539578 -225.522536)
		(mid 86.408664 -225.386176)
		(end 86.361016 -225.203258)
		(width 0.088646)
		(layer "In2.Cu")
		(net "M_B_CPU1_SB_DQS_DN<2>")
	)
	(arc
		(start 87.488014 -227.155502)
		(mid 87.350989 -227.018389)
		(end 87.300816 -226.831144)
		(width 0.088646)
		(layer "In2.Cu")
		(net "M_B_CPU1_SB_DQS_DN<2>")
	)
	(arc
		(start 86.361016 -225.193352)
		(mid 86.282905 -224.916403)
		(end 86.078568 -224.7138)
		(width 0.088646)
		(layer "In2.Cu")
		(net "M_B_CPU1_SB_DQS_DN<2>")
	)
	(arc
		(start 86.069678 -224.70872)
		(mid 85.938764 -224.57236)
		(end 85.891116 -224.389442)
		(width 0.088646)
		(layer "In2.Cu")
		(net "M_B_CPU1_SB_DQS_DN<2>")
	)
	(arc
		(start 84.54009 -223.106488)
		(mid 84.496396 -223.138881)
		(end 84.456016 -223.175322)
		(width 0.088646)
		(layer "In2.Cu")
		(net "M_B_CPU1_SB_DQS_DN<2>")
	)
	(arc
		(start 85.599778 -223.894904)
		(mid 85.468864 -223.758544)
		(end 85.421216 -223.575626)
		(width 0.088646)
		(layer "In2.Cu")
		(net "M_B_CPU1_SB_DQS_DN<2>")
	)
	(arc
		(start 85.891116 -224.389442)
		(mid 85.8172 -224.10994)
		(end 85.614764 -223.90354)
		(width 0.088646)
		(layer "In2.Cu")
		(net "M_B_CPU1_SB_DQS_DN<2>")
	)
	(arc
		(start 87.018114 -226.341686)
		(mid 86.883181 -226.208332)
		(end 86.830916 -226.025964)
		(width 0.088646)
		(layer "In2.Cu")
		(net "M_B_CPU1_SB_DQS_DN<2>")
	)
	(arc
		(start 87.300816 -226.831144)
		(mid 87.228581 -226.55462)
		(end 87.030306 -226.348798)
		(width 0.088646)
		(layer "In2.Cu")
		(net "M_B_CPU1_SB_DQS_DN<2>")
	)
	(arc
		(start 86.830916 -225.998786)
		(mid 86.750754 -225.726597)
		(end 86.548468 -225.527616)
		(width 0.088646)
		(layer "In2.Cu")
		(net "M_B_CPU1_SB_DQS_DN<2>")
	)
	(arc
		(start 85.421216 -223.561402)
		(mid 85.341997 -223.286717)
		(end 85.138514 -223.085914)
		(width 0.088646)
		(layer "In2.Cu")
		(net "M_B_CPU1_SB_DQS_DN<2>")
	)
	(arc
		(start 85.123782 -223.077278)
		(mid 84.847341 -223.010112)
		(end 84.57311 -223.085914)
		(width 0.088646)
		(layer "In2.Cu")
		(net "M_B_CPU1_SB_DQS_DN<2>")
	)
	(arc
		(start 84.57311 -223.085914)
		(mid 84.556424 -223.095919)
		(end 84.54009 -223.106488)
		(width 0.088646)
		(layer "In2.Cu")
		(net "M_B_CPU1_SB_DQS_DN<2>")
	)
	(segment
		(start 40.81526 -219.253054)
		(end 40.275002 -219.253054)
		(width 0.20066)
		(layer "F.Cu")
		(net "M_B_CPU1_SB_DQS_DN<1>")
	)
	(segment
		(start 41.087294 -218.98102)
		(end 40.81526 -219.253054)
		(width 0.20066)
		(layer "F.Cu")
		(net "M_B_CPU1_SB_DQS_DN<1>")
	)
	(segment
		(start 44.645072 -218.827858)
		(end 44.219876 -219.253054)
		(width 0.20066)
		(layer "F.Cu")
		(net "M_B_CPU1_SB_DQS_DN<1>")
	)
	(segment
		(start 43.616626 -218.991688)
		(end 41.30294 -218.991688)
		(width 0.1016)
		(layer "F.Cu")
		(net "M_B_CPU1_SB_DQS_DN<1>")
	)
	(segment
		(start 38.864286 -218.566746)
		(end 38.315646 -218.566746)
		(width 0.20066)
		(layer "F.Cu")
		(net "M_B_CPU1_SB_DQS_DN<1>")
	)
	(segment
		(start 40.275002 -219.253054)
		(end 39.63924 -218.827858)
		(width 0.20066)
		(layer "F.Cu")
		(net "M_B_CPU1_SB_DQS_DN<1>")
	)
	(segment
		(start 41.29151 -218.98102)
		(end 41.087294 -218.98102)
		(width 0.20066)
		(layer "F.Cu")
		(net "M_B_CPU1_SB_DQS_DN<1>")
	)
	(segment
		(start 44.219876 -219.253054)
		(end 44.033186 -219.253054)
		(width 0.20066)
		(layer "F.Cu")
		(net "M_B_CPU1_SB_DQS_DN<1>")
	)
	(segment
		(start 46.964346 -218.566746)
		(end 45.859446 -218.566746)
		(width 0.20066)
		(layer "F.Cu")
		(net "M_B_CPU1_SB_DQS_DN<1>")
	)
	(segment
		(start 45.312838 -218.566746)
		(end 45.051726 -218.827858)
		(width 0.20066)
		(layer "F.Cu")
		(net "M_B_CPU1_SB_DQS_DN<1>")
	)
	(segment
		(start 45.051726 -218.827858)
		(end 44.645072 -218.827858)
		(width 0.20066)
		(layer "F.Cu")
		(net "M_B_CPU1_SB_DQS_DN<1>")
	)
	(segment
		(start 44.033186 -219.253054)
		(end 43.77182 -218.991688)
		(width 0.20066)
		(layer "F.Cu")
		(net "M_B_CPU1_SB_DQS_DN<1>")
	)
	(segment
		(start 39.63924 -218.827858)
		(end 39.125398 -218.827858)
		(width 0.20066)
		(layer "F.Cu")
		(net "M_B_CPU1_SB_DQS_DN<1>")
	)
	(segment
		(start 43.77182 -218.991688)
		(end 43.616626 -218.991688)
		(width 0.20066)
		(layer "F.Cu")
		(net "M_B_CPU1_SB_DQS_DN<1>")
	)
	(segment
		(start 88.145366 -233.064304)
		(end 88.145366 -232.528364)
		(width 0.20066)
		(layer "F.Cu")
		(net "M_B_CPU1_SB_DQS_DN<1>")
	)
	(segment
		(start 45.859446 -218.566746)
		(end 45.312838 -218.566746)
		(width 0.20066)
		(layer "F.Cu")
		(net "M_B_CPU1_SB_DQS_DN<1>")
	)
	(segment
		(start 39.125398 -218.827858)
		(end 38.864286 -218.566746)
		(width 0.20066)
		(layer "F.Cu")
		(net "M_B_CPU1_SB_DQS_DN<1>")
	)
	(segment
		(start 41.30294 -218.991688)
		(end 41.292272 -218.98102)
		(width 0.101854)
		(layer "F.Cu")
		(net "M_B_CPU1_SB_DQS_DN<1>")
	)
	(segment
		(start 41.292272 -218.98102)
		(end 41.29151 -218.98102)
		(width 0.101854)
		(layer "F.Cu")
		(net "M_B_CPU1_SB_DQS_DN<1>")
	)
	(segment
		(start 85.138514 -232.852722)
		(end 85.123782 -232.844086)
		(width 0.088646)
		(layer "In2.Cu")
		(net "M_B_CPU1_SB_DQS_DN<1>")
	)
	(segment
		(start 83.255866 -232.320084)
		(end 83.255866 -232.235756)
		(width 0.088646)
		(layer "In2.Cu")
		(net "M_B_CPU1_SB_DQS_DN<1>")
	)
	(segment
		(start 74.308208 -223.112076)
		(end 73.920096 -222.723964)
		(width 0.18288)
		(layer "In2.Cu")
		(net "M_B_CPU1_SB_DQS_DN<1>")
	)
	(segment
		(start 59.294776 -219.58935)
		(end 58.50128 -220.382846)
		(width 0.18288)
		(layer "In2.Cu")
		(net "M_B_CPU1_SB_DQS_DN<1>")
	)
	(segment
		(start 54.128924 -219.804996)
		(end 54.05501 -219.87891)
		(width 0.18288)
		(layer "In2.Cu")
		(net "M_B_CPU1_SB_DQS_DN<1>")
	)
	(segment
		(start 63.392812 -218.53652)
		(end 62.683898 -219.245434)
		(width 0.18288)
		(layer "In2.Cu")
		(net "M_B_CPU1_SB_DQS_DN<1>")
	)
	(segment
		(start 54.373018 -219.577158)
		(end 54.173374 -219.776802)
		(width 0.16002)
		(layer "In2.Cu")
		(net "M_B_CPU1_SB_DQS_DN<1>")
	)
	(segment
		(start 49.330102 -219.066618)
		(end 49.313846 -219.066618)
		(width 0.16002)
		(layer "In2.Cu")
		(net "M_B_CPU1_SB_DQS_DN<1>")
	)
	(segment
		(start 52.40528 -219.532708)
		(end 52.131468 -219.258896)
		(width 0.18288)
		(layer "In2.Cu")
		(net "M_B_CPU1_SB_DQS_DN<1>")
	)
	(segment
		(start 56.749442 -220.62694)
		(end 56.733186 -220.62694)
		(width 0.16002)
		(layer "In2.Cu")
		(net "M_B_CPU1_SB_DQS_DN<1>")
	)
	(segment
		(start 71.452232 -220.2561)
		(end 71.06412 -219.867988)
		(width 0.18288)
		(layer "In2.Cu")
		(net "M_B_CPU1_SB_DQS_DN<1>")
	)
	(segment
		(start 61.717174 -219.776802)
		(end 61.700918 -219.776802)
		(width 0.16002)
		(layer "In2.Cu")
		(net "M_B_CPU1_SB_DQS_DN<1>")
	)
	(segment
		(start 65.698878 -219.029026)
		(end 64.39535 -219.029026)
		(width 0.18288)
		(layer "In2.Cu")
		(net "M_B_CPU1_SB_DQS_DN<1>")
	)
	(segment
		(start 66.016886 -218.711018)
		(end 66.016886 -218.727274)
		(width 0.16002)
		(layer "In2.Cu")
		(net "M_B_CPU1_SB_DQS_DN<1>")
	)
	(segment
		(start 64.321436 -218.955112)
		(end 64.293242 -218.926918)
		(width 0.16002)
		(layer "In2.Cu")
		(net "M_B_CPU1_SB_DQS_DN<1>")
	)
	(segment
		(start 52.131468 -219.258896)
		(end 51.513994 -219.258896)
		(width 0.18288)
		(layer "In2.Cu")
		(net "M_B_CPU1_SB_DQS_DN<1>")
	)
	(segment
		(start 49.313846 -219.066618)
		(end 49.114202 -218.866974)
		(width 0.16002)
		(layer "In2.Cu")
		(net "M_B_CPU1_SB_DQS_DN<1>")
	)
	(segment
		(start 66.04508 -218.682824)
		(end 66.016886 -218.711018)
		(width 0.16002)
		(layer "In2.Cu")
		(net "M_B_CPU1_SB_DQS_DN<1>")
	)
	(segment
		(start 54.373018 -219.560902)
		(end 54.373018 -219.577158)
		(width 0.16002)
		(layer "In2.Cu")
		(net "M_B_CPU1_SB_DQS_DN<1>")
	)
	(segment
		(start 75.2602 -224.064068)
		(end 74.872088 -223.675956)
		(width 0.18288)
		(layer "In2.Cu")
		(net "M_B_CPU1_SB_DQS_DN<1>")
	)
	(segment
		(start 61.700918 -219.776802)
		(end 61.672724 -219.804996)
		(width 0.16002)
		(layer "In2.Cu")
		(net "M_B_CPU1_SB_DQS_DN<1>")
	)
	(segment
		(start 49.358296 -219.094812)
		(end 49.330102 -219.066618)
		(width 0.16002)
		(layer "In2.Cu")
		(net "M_B_CPU1_SB_DQS_DN<1>")
	)
	(segment
		(start 47.234348 -218.836748)
		(end 46.964346 -218.566746)
		(width 0.18288)
		(layer "In2.Cu")
		(net "M_B_CPU1_SB_DQS_DN<1>")
	)
	(segment
		(start 72.792082 -221.771972)
		(end 72.404224 -221.384114)
		(width 0.18288)
		(layer "In2.Cu")
		(net "M_B_CPU1_SB_DQS_DN<1>")
	)
	(segment
		(start 52.649374 -219.776802)
		(end 52.633118 -219.776802)
		(width 0.16002)
		(layer "In2.Cu")
		(net "M_B_CPU1_SB_DQS_DN<1>")
	)
	(segment
		(start 54.60619 -219.32773)
		(end 54.401212 -219.532708)
		(width 0.18288)
		(layer "In2.Cu")
		(net "M_B_CPU1_SB_DQS_DN<1>")
	)
	(segment
		(start 84.385912 -232.903014)
		(end 84.123022 -232.903014)
		(width 0.088646)
		(layer "In2.Cu")
		(net "M_B_CPU1_SB_DQS_DN<1>")
	)
	(segment
		(start 67.653408 -218.528138)
		(end 67.528948 -218.403678)
		(width 0.18288)
		(layer "In2.Cu")
		(net "M_B_CPU1_SB_DQS_DN<1>")
	)
	(segment
		(start 55.450232 -219.32773)
		(end 54.60619 -219.32773)
		(width 0.18288)
		(layer "In2.Cu")
		(net "M_B_CPU1_SB_DQS_DN<1>")
	)
	(segment
		(start 83.255866 -232.235756)
		(end 75.2602 -224.24009)
		(width 0.18288)
		(layer "In2.Cu")
		(net "M_B_CPU1_SB_DQS_DN<1>")
	)
	(segment
		(start 68.326508 -218.403678)
		(end 68.202048 -218.528138)
		(width 0.18288)
		(layer "In2.Cu")
		(net "M_B_CPU1_SB_DQS_DN<1>")
	)
	(segment
		(start 65.817242 -218.926918)
		(end 65.800986 -218.926918)
		(width 0.16002)
		(layer "In2.Cu")
		(net "M_B_CPU1_SB_DQS_DN<1>")
	)
	(segment
		(start 61.945012 -219.532708)
		(end 61.916818 -219.560902)
		(width 0.16002)
		(layer "In2.Cu")
		(net "M_B_CPU1_SB_DQS_DN<1>")
	)
	(segment
		(start 64.39535 -219.029026)
		(end 64.321436 -218.955112)
		(width 0.18288)
		(layer "In2.Cu")
		(net "M_B_CPU1_SB_DQS_DN<1>")
	)
	(segment
		(start 83.410806 -232.475024)
		(end 83.255866 -232.320084)
		(width 0.088646)
		(layer "In2.Cu")
		(net "M_B_CPU1_SB_DQS_DN<1>")
	)
	(segment
		(start 71.84009 -220.81998)
		(end 71.452232 -220.432122)
		(width 0.18288)
		(layer "In2.Cu")
		(net "M_B_CPU1_SB_DQS_DN<1>")
	)
	(segment
		(start 64.049148 -218.682824)
		(end 63.902844 -218.53652)
		(width 0.18288)
		(layer "In2.Cu")
		(net "M_B_CPU1_SB_DQS_DN<1>")
	)
	(segment
		(start 58.155078 -220.729048)
		(end 56.85155 -220.729048)
		(width 0.18288)
		(layer "In2.Cu")
		(net "M_B_CPU1_SB_DQS_DN<1>")
	)
	(segment
		(start 58.473086 -220.427296)
		(end 58.273442 -220.62694)
		(width 0.16002)
		(layer "In2.Cu")
		(net "M_B_CPU1_SB_DQS_DN<1>")
	)
	(segment
		(start 83.695032 -232.475024)
		(end 83.410806 -232.475024)
		(width 0.088646)
		(layer "In2.Cu")
		(net "M_B_CPU1_SB_DQS_DN<1>")
	)
	(segment
		(start 68.202048 -218.528138)
		(end 67.653408 -218.528138)
		(width 0.18288)
		(layer "In2.Cu")
		(net "M_B_CPU1_SB_DQS_DN<1>")
	)
	(segment
		(start 49.114202 -218.866974)
		(end 49.114202 -218.850718)
		(width 0.16002)
		(layer "In2.Cu")
		(net "M_B_CPU1_SB_DQS_DN<1>")
	)
	(segment
		(start 74.308208 -223.288098)
		(end 74.308208 -223.112076)
		(width 0.18288)
		(layer "In2.Cu")
		(net "M_B_CPU1_SB_DQS_DN<1>")
	)
	(segment
		(start 64.293242 -218.926918)
		(end 64.276986 -218.926918)
		(width 0.16002)
		(layer "In2.Cu")
		(net "M_B_CPU1_SB_DQS_DN<1>")
	)
	(segment
		(start 70.888098 -219.867988)
		(end 70.50024 -219.48013)
		(width 0.18288)
		(layer "In2.Cu")
		(net "M_B_CPU1_SB_DQS_DN<1>")
	)
	(segment
		(start 87.601044 -232.73258)
		(end 87.392764 -232.852722)
		(width 0.088646)
		(layer "In2.Cu")
		(net "M_B_CPU1_SB_DQS_DN<1>")
	)
	(segment
		(start 48.20031 -218.581224)
		(end 47.58309 -218.836748)
		(width 0.18288)
		(layer "In2.Cu")
		(net "M_B_CPU1_SB_DQS_DN<1>")
	)
	(segment
		(start 71.06412 -219.867988)
		(end 70.888098 -219.867988)
		(width 0.18288)
		(layer "In2.Cu")
		(net "M_B_CPU1_SB_DQS_DN<1>")
	)
	(segment
		(start 71.452232 -220.432122)
		(end 71.452232 -220.2561)
		(width 0.18288)
		(layer "In2.Cu")
		(net "M_B_CPU1_SB_DQS_DN<1>")
	)
	(segment
		(start 47.58309 -218.836748)
		(end 47.234348 -218.836748)
		(width 0.18288)
		(layer "In2.Cu")
		(net "M_B_CPU1_SB_DQS_DN<1>")
	)
	(segment
		(start 56.505348 -220.382846)
		(end 55.450232 -219.32773)
		(width 0.18288)
		(layer "In2.Cu")
		(net "M_B_CPU1_SB_DQS_DN<1>")
	)
	(segment
		(start 68.875148 -218.403678)
		(end 68.326508 -218.403678)
		(width 0.18288)
		(layer "In2.Cu")
		(net "M_B_CPU1_SB_DQS_DN<1>")
	)
	(segment
		(start 54.157118 -219.776802)
		(end 54.128924 -219.804996)
		(width 0.16002)
		(layer "In2.Cu")
		(net "M_B_CPU1_SB_DQS_DN<1>")
	)
	(segment
		(start 70.50024 -219.304108)
		(end 70.112128 -218.915996)
		(width 0.18288)
		(layer "In2.Cu")
		(net "M_B_CPU1_SB_DQS_DN<1>")
	)
	(segment
		(start 49.086008 -218.822524)
		(end 48.844708 -218.581224)
		(width 0.18288)
		(layer "In2.Cu")
		(net "M_B_CPU1_SB_DQS_DN<1>")
	)
	(segment
		(start 65.772792 -218.955112)
		(end 65.698878 -219.029026)
		(width 0.18288)
		(layer "In2.Cu")
		(net "M_B_CPU1_SB_DQS_DN<1>")
	)
	(segment
		(start 62.232286 -219.245434)
		(end 61.945012 -219.532708)
		(width 0.18288)
		(layer "In2.Cu")
		(net "M_B_CPU1_SB_DQS_DN<1>")
	)
	(segment
		(start 64.276986 -218.926918)
		(end 64.077342 -218.727274)
		(width 0.16002)
		(layer "In2.Cu")
		(net "M_B_CPU1_SB_DQS_DN<1>")
	)
	(segment
		(start 72.404224 -221.208092)
		(end 72.016112 -220.81998)
		(width 0.18288)
		(layer "In2.Cu")
		(net "M_B_CPU1_SB_DQS_DN<1>")
	)
	(segment
		(start 70.112128 -218.915996)
		(end 69.936106 -218.915996)
		(width 0.18288)
		(layer "In2.Cu")
		(net "M_B_CPU1_SB_DQS_DN<1>")
	)
	(segment
		(start 56.533542 -220.41104)
		(end 56.505348 -220.382846)
		(width 0.16002)
		(layer "In2.Cu")
		(net "M_B_CPU1_SB_DQS_DN<1>")
	)
	(segment
		(start 49.114202 -218.850718)
		(end 49.086008 -218.822524)
		(width 0.16002)
		(layer "In2.Cu")
		(net "M_B_CPU1_SB_DQS_DN<1>")
	)
	(segment
		(start 84.123022 -232.903014)
		(end 83.695032 -232.475024)
		(width 0.088646)
		(layer "In2.Cu")
		(net "M_B_CPU1_SB_DQS_DN<1>")
	)
	(segment
		(start 61.59627 -219.88145)
		(end 60.241942 -219.88145)
		(width 0.18288)
		(layer "In2.Cu")
		(net "M_B_CPU1_SB_DQS_DN<1>")
	)
	(segment
		(start 86.078568 -232.852722)
		(end 86.068154 -232.846626)
		(width 0.088646)
		(layer "In2.Cu")
		(net "M_B_CPU1_SB_DQS_DN<1>")
	)
	(segment
		(start 58.473086 -220.41104)
		(end 58.473086 -220.427296)
		(width 0.16002)
		(layer "In2.Cu")
		(net "M_B_CPU1_SB_DQS_DN<1>")
	)
	(segment
		(start 49.537874 -219.27439)
		(end 49.358296 -219.094812)
		(width 0.18288)
		(layer "In2.Cu")
		(net "M_B_CPU1_SB_DQS_DN<1>")
	)
	(segment
		(start 66.980308 -218.403678)
		(end 66.855848 -218.528138)
		(width 0.18288)
		(layer "In2.Cu")
		(net "M_B_CPU1_SB_DQS_DN<1>")
	)
	(segment
		(start 56.85155 -220.729048)
		(end 56.777636 -220.655134)
		(width 0.18288)
		(layer "In2.Cu")
		(net "M_B_CPU1_SB_DQS_DN<1>")
	)
	(segment
		(start 72.016112 -220.81998)
		(end 71.84009 -220.81998)
		(width 0.18288)
		(layer "In2.Cu")
		(net "M_B_CPU1_SB_DQS_DN<1>")
	)
	(segment
		(start 52.633118 -219.776802)
		(end 52.433474 -219.577158)
		(width 0.16002)
		(layer "In2.Cu")
		(net "M_B_CPU1_SB_DQS_DN<1>")
	)
	(segment
		(start 48.844708 -218.581224)
		(end 48.20031 -218.581224)
		(width 0.18288)
		(layer "In2.Cu")
		(net "M_B_CPU1_SB_DQS_DN<1>")
	)
	(segment
		(start 58.273442 -220.62694)
		(end 58.257186 -220.62694)
		(width 0.16002)
		(layer "In2.Cu")
		(net "M_B_CPU1_SB_DQS_DN<1>")
	)
	(segment
		(start 73.356216 -222.336106)
		(end 73.356216 -222.160084)
		(width 0.18288)
		(layer "In2.Cu")
		(net "M_B_CPU1_SB_DQS_DN<1>")
	)
	(segment
		(start 73.920096 -222.723964)
		(end 73.744074 -222.723964)
		(width 0.18288)
		(layer "In2.Cu")
		(net "M_B_CPU1_SB_DQS_DN<1>")
	)
	(segment
		(start 72.968104 -221.771972)
		(end 72.792082 -221.771972)
		(width 0.18288)
		(layer "In2.Cu")
		(net "M_B_CPU1_SB_DQS_DN<1>")
	)
	(segment
		(start 54.173374 -219.776802)
		(end 54.157118 -219.776802)
		(width 0.16002)
		(layer "In2.Cu")
		(net "M_B_CPU1_SB_DQS_DN<1>")
	)
	(segment
		(start 58.228992 -220.655134)
		(end 58.155078 -220.729048)
		(width 0.18288)
		(layer "In2.Cu")
		(net "M_B_CPU1_SB_DQS_DN<1>")
	)
	(segment
		(start 66.855848 -218.528138)
		(end 66.199766 -218.528138)
		(width 0.18288)
		(layer "In2.Cu")
		(net "M_B_CPU1_SB_DQS_DN<1>")
	)
	(segment
		(start 51.246786 -218.991688)
		(end 50.870104 -218.991688)
		(width 0.18288)
		(layer "In2.Cu")
		(net "M_B_CPU1_SB_DQS_DN<1>")
	)
	(segment
		(start 56.777636 -220.655134)
		(end 56.749442 -220.62694)
		(width 0.16002)
		(layer "In2.Cu")
		(net "M_B_CPU1_SB_DQS_DN<1>")
	)
	(segment
		(start 51.513994 -219.258896)
		(end 51.246786 -218.991688)
		(width 0.18288)
		(layer "In2.Cu")
		(net "M_B_CPU1_SB_DQS_DN<1>")
	)
	(segment
		(start 75.2602 -224.24009)
		(end 75.2602 -224.064068)
		(width 0.18288)
		(layer "In2.Cu")
		(net "M_B_CPU1_SB_DQS_DN<1>")
	)
	(segment
		(start 64.077342 -218.711018)
		(end 64.049148 -218.682824)
		(width 0.16002)
		(layer "In2.Cu")
		(net "M_B_CPU1_SB_DQS_DN<1>")
	)
	(segment
		(start 52.433474 -219.577158)
		(end 52.433474 -219.560902)
		(width 0.16002)
		(layer "In2.Cu")
		(net "M_B_CPU1_SB_DQS_DN<1>")
	)
	(segment
		(start 67.528948 -218.403678)
		(end 66.980308 -218.403678)
		(width 0.18288)
		(layer "In2.Cu")
		(net "M_B_CPU1_SB_DQS_DN<1>")
	)
	(segment
		(start 50.870104 -218.991688)
		(end 50.587402 -219.27439)
		(width 0.18288)
		(layer "In2.Cu")
		(net "M_B_CPU1_SB_DQS_DN<1>")
	)
	(segment
		(start 65.800986 -218.926918)
		(end 65.772792 -218.955112)
		(width 0.16002)
		(layer "In2.Cu")
		(net "M_B_CPU1_SB_DQS_DN<1>")
	)
	(segment
		(start 66.199766 -218.528138)
		(end 66.04508 -218.682824)
		(width 0.18288)
		(layer "In2.Cu")
		(net "M_B_CPU1_SB_DQS_DN<1>")
	)
	(segment
		(start 61.916818 -219.577158)
		(end 61.717174 -219.776802)
		(width 0.16002)
		(layer "In2.Cu")
		(net "M_B_CPU1_SB_DQS_DN<1>")
	)
	(segment
		(start 56.733186 -220.62694)
		(end 56.533542 -220.427296)
		(width 0.16002)
		(layer "In2.Cu")
		(net "M_B_CPU1_SB_DQS_DN<1>")
	)
	(segment
		(start 50.587402 -219.27439)
		(end 49.537874 -219.27439)
		(width 0.18288)
		(layer "In2.Cu")
		(net "M_B_CPU1_SB_DQS_DN<1>")
	)
	(segment
		(start 54.05501 -219.87891)
		(end 52.751482 -219.87891)
		(width 0.18288)
		(layer "In2.Cu")
		(net "M_B_CPU1_SB_DQS_DN<1>")
	)
	(segment
		(start 70.50024 -219.48013)
		(end 70.50024 -219.304108)
		(width 0.18288)
		(layer "In2.Cu")
		(net "M_B_CPU1_SB_DQS_DN<1>")
	)
	(segment
		(start 62.683898 -219.245434)
		(end 62.232286 -219.245434)
		(width 0.18288)
		(layer "In2.Cu")
		(net "M_B_CPU1_SB_DQS_DN<1>")
	)
	(segment
		(start 64.077342 -218.727274)
		(end 64.077342 -218.711018)
		(width 0.16002)
		(layer "In2.Cu")
		(net "M_B_CPU1_SB_DQS_DN<1>")
	)
	(segment
		(start 58.50128 -220.382846)
		(end 58.473086 -220.41104)
		(width 0.16002)
		(layer "In2.Cu")
		(net "M_B_CPU1_SB_DQS_DN<1>")
	)
	(segment
		(start 59.949842 -219.58935)
		(end 59.294776 -219.58935)
		(width 0.18288)
		(layer "In2.Cu")
		(net "M_B_CPU1_SB_DQS_DN<1>")
	)
	(segment
		(start 54.401212 -219.532708)
		(end 54.373018 -219.560902)
		(width 0.16002)
		(layer "In2.Cu")
		(net "M_B_CPU1_SB_DQS_DN<1>")
	)
	(segment
		(start 63.902844 -218.53652)
		(end 63.392812 -218.53652)
		(width 0.18288)
		(layer "In2.Cu")
		(net "M_B_CPU1_SB_DQS_DN<1>")
	)
	(segment
		(start 69.548248 -218.528138)
		(end 68.999608 -218.528138)
		(width 0.18288)
		(layer "In2.Cu")
		(net "M_B_CPU1_SB_DQS_DN<1>")
	)
	(segment
		(start 73.744074 -222.723964)
		(end 73.356216 -222.336106)
		(width 0.18288)
		(layer "In2.Cu")
		(net "M_B_CPU1_SB_DQS_DN<1>")
	)
	(segment
		(start 61.916818 -219.560902)
		(end 61.916818 -219.577158)
		(width 0.16002)
		(layer "In2.Cu")
		(net "M_B_CPU1_SB_DQS_DN<1>")
	)
	(segment
		(start 73.356216 -222.160084)
		(end 72.968104 -221.771972)
		(width 0.18288)
		(layer "In2.Cu")
		(net "M_B_CPU1_SB_DQS_DN<1>")
	)
	(segment
		(start 88.145366 -232.528364)
		(end 87.94115 -232.73258)
		(width 0.088646)
		(layer "In2.Cu")
		(net "M_B_CPU1_SB_DQS_DN<1>")
	)
	(segment
		(start 56.533542 -220.427296)
		(end 56.533542 -220.41104)
		(width 0.16002)
		(layer "In2.Cu")
		(net "M_B_CPU1_SB_DQS_DN<1>")
	)
	(segment
		(start 87.94115 -232.73258)
		(end 87.601044 -232.73258)
		(width 0.088646)
		(layer "In2.Cu")
		(net "M_B_CPU1_SB_DQS_DN<1>")
	)
	(segment
		(start 52.677568 -219.804996)
		(end 52.649374 -219.776802)
		(width 0.16002)
		(layer "In2.Cu")
		(net "M_B_CPU1_SB_DQS_DN<1>")
	)
	(segment
		(start 61.672724 -219.804996)
		(end 61.59627 -219.88145)
		(width 0.18288)
		(layer "In2.Cu")
		(net "M_B_CPU1_SB_DQS_DN<1>")
	)
	(segment
		(start 60.241942 -219.88145)
		(end 59.949842 -219.58935)
		(width 0.18288)
		(layer "In2.Cu")
		(net "M_B_CPU1_SB_DQS_DN<1>")
	)
	(segment
		(start 66.016886 -218.727274)
		(end 65.817242 -218.926918)
		(width 0.16002)
		(layer "In2.Cu")
		(net "M_B_CPU1_SB_DQS_DN<1>")
	)
	(segment
		(start 72.404224 -221.384114)
		(end 72.404224 -221.208092)
		(width 0.18288)
		(layer "In2.Cu")
		(net "M_B_CPU1_SB_DQS_DN<1>")
	)
	(segment
		(start 74.696066 -223.675956)
		(end 74.308208 -223.288098)
		(width 0.18288)
		(layer "In2.Cu")
		(net "M_B_CPU1_SB_DQS_DN<1>")
	)
	(segment
		(start 52.751482 -219.87891)
		(end 52.677568 -219.804996)
		(width 0.18288)
		(layer "In2.Cu")
		(net "M_B_CPU1_SB_DQS_DN<1>")
	)
	(segment
		(start 68.999608 -218.528138)
		(end 68.875148 -218.403678)
		(width 0.18288)
		(layer "In2.Cu")
		(net "M_B_CPU1_SB_DQS_DN<1>")
	)
	(segment
		(start 52.433474 -219.560902)
		(end 52.40528 -219.532708)
		(width 0.16002)
		(layer "In2.Cu")
		(net "M_B_CPU1_SB_DQS_DN<1>")
	)
	(segment
		(start 58.257186 -220.62694)
		(end 58.228992 -220.655134)
		(width 0.16002)
		(layer "In2.Cu")
		(net "M_B_CPU1_SB_DQS_DN<1>")
	)
	(segment
		(start 69.936106 -218.915996)
		(end 69.548248 -218.528138)
		(width 0.18288)
		(layer "In2.Cu")
		(net "M_B_CPU1_SB_DQS_DN<1>")
	)
	(segment
		(start 74.872088 -223.675956)
		(end 74.696066 -223.675956)
		(width 0.18288)
		(layer "In2.Cu")
		(net "M_B_CPU1_SB_DQS_DN<1>")
	)
	(arc
		(start 86.452964 -232.852722)
		(mid 86.265766 -232.902865)
		(end 86.078568 -232.852722)
		(width 0.088646)
		(layer "In2.Cu")
		(net "M_B_CPU1_SB_DQS_DN<1>")
	)
	(arc
		(start 87.018368 -232.852722)
		(mid 86.735666 -232.776946)
		(end 86.452964 -232.852722)
		(width 0.088646)
		(layer "In2.Cu")
		(net "M_B_CPU1_SB_DQS_DN<1>")
	)
	(arc
		(start 85.51291 -232.852722)
		(mid 85.325712 -232.902865)
		(end 85.138514 -232.852722)
		(width 0.088646)
		(layer "In2.Cu")
		(net "M_B_CPU1_SB_DQS_DN<1>")
	)
	(arc
		(start 87.392764 -232.852722)
		(mid 87.205566 -232.902865)
		(end 87.018368 -232.852722)
		(width 0.088646)
		(layer "In2.Cu")
		(net "M_B_CPU1_SB_DQS_DN<1>")
	)
	(arc
		(start 86.068154 -232.846626)
		(mid 85.789722 -232.77678)
		(end 85.51291 -232.852722)
		(width 0.088646)
		(layer "In2.Cu")
		(net "M_B_CPU1_SB_DQS_DN<1>")
	)
	(arc
		(start 84.57311 -232.852722)
		(mid 84.482818 -232.890174)
		(end 84.385912 -232.903014)
		(width 0.088646)
		(layer "In2.Cu")
		(net "M_B_CPU1_SB_DQS_DN<1>")
	)
	(arc
		(start 85.123782 -232.844086)
		(mid 84.847307 -232.776766)
		(end 84.57311 -232.852722)
		(width 0.088646)
		(layer "In2.Cu")
		(net "M_B_CPU1_SB_DQS_DN<1>")
	)
	(segment
		(start 91.434666 -235.506006)
		(end 91.434412 -235.505752)
		(width 0.20066)
		(layer "F.Cu")
		(net "M_B_CPU1_SB_DQS_DN<0>")
	)
	(segment
		(start 45.312838 -227.91674)
		(end 45.051726 -228.177852)
		(width 0.20066)
		(layer "F.Cu")
		(net "M_B_CPU1_SB_DQS_DN<0>")
	)
	(segment
		(start 38.864286 -227.91674)
		(end 38.315646 -227.91674)
		(width 0.20066)
		(layer "F.Cu")
		(net "M_B_CPU1_SB_DQS_DN<0>")
	)
	(segment
		(start 43.77182 -228.341682)
		(end 43.616626 -228.341682)
		(width 0.20066)
		(layer "F.Cu")
		(net "M_B_CPU1_SB_DQS_DN<0>")
	)
	(segment
		(start 46.964346 -227.91674)
		(end 45.859446 -227.91674)
		(width 0.20066)
		(layer "F.Cu")
		(net "M_B_CPU1_SB_DQS_DN<0>")
	)
	(segment
		(start 41.087294 -228.331014)
		(end 40.81526 -228.603048)
		(width 0.20066)
		(layer "F.Cu")
		(net "M_B_CPU1_SB_DQS_DN<0>")
	)
	(segment
		(start 41.30294 -228.341682)
		(end 41.292272 -228.331014)
		(width 0.101854)
		(layer "F.Cu")
		(net "M_B_CPU1_SB_DQS_DN<0>")
	)
	(segment
		(start 41.292272 -228.331014)
		(end 41.29151 -228.331014)
		(width 0.101854)
		(layer "F.Cu")
		(net "M_B_CPU1_SB_DQS_DN<0>")
	)
	(segment
		(start 91.434412 -235.505752)
		(end 91.434412 -234.970066)
		(width 0.20066)
		(layer "F.Cu")
		(net "M_B_CPU1_SB_DQS_DN<0>")
	)
	(segment
		(start 45.051726 -228.177852)
		(end 44.645072 -228.177852)
		(width 0.20066)
		(layer "F.Cu")
		(net "M_B_CPU1_SB_DQS_DN<0>")
	)
	(segment
		(start 45.859446 -227.91674)
		(end 45.312838 -227.91674)
		(width 0.20066)
		(layer "F.Cu")
		(net "M_B_CPU1_SB_DQS_DN<0>")
	)
	(segment
		(start 44.033186 -228.603048)
		(end 43.77182 -228.341682)
		(width 0.20066)
		(layer "F.Cu")
		(net "M_B_CPU1_SB_DQS_DN<0>")
	)
	(segment
		(start 39.63924 -228.177852)
		(end 39.125398 -228.177852)
		(width 0.20066)
		(layer "F.Cu")
		(net "M_B_CPU1_SB_DQS_DN<0>")
	)
	(segment
		(start 40.81526 -228.603048)
		(end 40.275256 -228.603048)
		(width 0.20066)
		(layer "F.Cu")
		(net "M_B_CPU1_SB_DQS_DN<0>")
	)
	(segment
		(start 41.29151 -228.331014)
		(end 41.087294 -228.331014)
		(width 0.20066)
		(layer "F.Cu")
		(net "M_B_CPU1_SB_DQS_DN<0>")
	)
	(segment
		(start 40.275256 -228.603048)
		(end 39.63924 -228.177852)
		(width 0.20066)
		(layer "F.Cu")
		(net "M_B_CPU1_SB_DQS_DN<0>")
	)
	(segment
		(start 44.645072 -228.177852)
		(end 44.219876 -228.603048)
		(width 0.20066)
		(layer "F.Cu")
		(net "M_B_CPU1_SB_DQS_DN<0>")
	)
	(segment
		(start 43.616626 -228.341682)
		(end 41.30294 -228.341682)
		(width 0.1016)
		(layer "F.Cu")
		(net "M_B_CPU1_SB_DQS_DN<0>")
	)
	(segment
		(start 39.125398 -228.177852)
		(end 38.864286 -227.91674)
		(width 0.20066)
		(layer "F.Cu")
		(net "M_B_CPU1_SB_DQS_DN<0>")
	)
	(segment
		(start 44.219876 -228.603048)
		(end 44.033186 -228.603048)
		(width 0.20066)
		(layer "F.Cu")
		(net "M_B_CPU1_SB_DQS_DN<0>")
	)
	(segment
		(start 55.585614 -227.722176)
		(end 55.461154 -227.846636)
		(width 0.18288)
		(layer "In4.Cu")
		(net "M_B_CPU1_SB_DQS_DN<0>")
	)
	(segment
		(start 57.429654 -227.282756)
		(end 57.429654 -227.458778)
		(width 0.18288)
		(layer "In4.Cu")
		(net "M_B_CPU1_SB_DQS_DN<0>")
	)
	(segment
		(start 64.81572 -228.023674)
		(end 64.427608 -227.635562)
		(width 0.18288)
		(layer "In4.Cu")
		(net "M_B_CPU1_SB_DQS_DN<0>")
	)
	(segment
		(start 91.402662 -235.08589)
		(end 91.3638 -235.107988)
		(width 0.088646)
		(layer "In4.Cu")
		(net "M_B_CPU1_SB_DQS_DN<0>")
	)
	(segment
		(start 72.489314 -233.326686)
		(end 72.313292 -233.326686)
		(width 0.18288)
		(layer "In4.Cu")
		(net "M_B_CPU1_SB_DQS_DN<0>")
	)
	(segment
		(start 59.19343 -226.259898)
		(end 58.805064 -226.648264)
		(width 0.18288)
		(layer "In4.Cu")
		(net "M_B_CPU1_SB_DQS_DN<0>")
	)
	(segment
		(start 82.746596 -235.23067)
		(end 82.708496 -235.23067)
		(width 0.088646)
		(layer "In4.Cu")
		(net "M_B_CPU1_SB_DQS_DN<0>")
	)
	(segment
		(start 91.434412 -234.970066)
		(end 91.402662 -235.08589)
		(width 0.088646)
		(layer "In4.Cu")
		(net "M_B_CPU1_SB_DQS_DN<0>")
	)
	(segment
		(start 50.841402 -228.341682)
		(end 50.53711 -228.645974)
		(width 0.18288)
		(layer "In4.Cu")
		(net "M_B_CPU1_SB_DQS_DN<0>")
	)
	(segment
		(start 57.817766 -226.894644)
		(end 57.429654 -227.282756)
		(width 0.18288)
		(layer "In4.Cu")
		(net "M_B_CPU1_SB_DQS_DN<0>")
	)
	(segment
		(start 57.993788 -226.894644)
		(end 57.817766 -226.894644)
		(width 0.18288)
		(layer "In4.Cu")
		(net "M_B_CPU1_SB_DQS_DN<0>")
	)
	(segment
		(start 68.505324 -229.518718)
		(end 67.5767 -228.590094)
		(width 0.18288)
		(layer "In4.Cu")
		(net "M_B_CPU1_SB_DQS_DN<0>")
	)
	(segment
		(start 48.893222 -227.820728)
		(end 48.344582 -227.820728)
		(width 0.18288)
		(layer "In4.Cu")
		(net "M_B_CPU1_SB_DQS_DN<0>")
	)
	(segment
		(start 64.251586 -227.635562)
		(end 63.51778 -226.901756)
		(width 0.18288)
		(layer "In4.Cu")
		(net "M_B_CPU1_SB_DQS_DN<0>")
	)
	(segment
		(start 53.566314 -227.846636)
		(end 53.071268 -228.341682)
		(width 0.18288)
		(layer "In4.Cu")
		(net "M_B_CPU1_SB_DQS_DN<0>")
	)
	(segment
		(start 66.59245 -228.590094)
		(end 66.347086 -228.34473)
		(width 0.18288)
		(layer "In4.Cu")
		(net "M_B_CPU1_SB_DQS_DN<0>")
	)
	(segment
		(start 55.461154 -227.846636)
		(end 54.912514 -227.846636)
		(width 0.18288)
		(layer "In4.Cu")
		(net "M_B_CPU1_SB_DQS_DN<0>")
	)
	(segment
		(start 56.258714 -227.846636)
		(end 56.134254 -227.722176)
		(width 0.18288)
		(layer "In4.Cu")
		(net "M_B_CPU1_SB_DQS_DN<0>")
	)
	(segment
		(start 69.457316 -230.47071)
		(end 69.069458 -230.082852)
		(width 0.18288)
		(layer "In4.Cu")
		(net "M_B_CPU1_SB_DQS_DN<0>")
	)
	(segment
		(start 60.518294 -226.259898)
		(end 59.19343 -226.259898)
		(width 0.18288)
		(layer "In4.Cu")
		(net "M_B_CPU1_SB_DQS_DN<0>")
	)
	(segment
		(start 88.427814 -235.294424)
		(end 88.413082 -235.285788)
		(width 0.088646)
		(layer "In4.Cu")
		(net "M_B_CPU1_SB_DQS_DN<0>")
	)
	(segment
		(start 72.313292 -233.326686)
		(end 71.925434 -232.938828)
		(width 0.18288)
		(layer "In4.Cu")
		(net "M_B_CPU1_SB_DQS_DN<0>")
	)
	(segment
		(start 89.367614 -235.294424)
		(end 89.352882 -235.285788)
		(width 0.088646)
		(layer "In4.Cu")
		(net "M_B_CPU1_SB_DQS_DN<0>")
	)
	(segment
		(start 87.488014 -235.294424)
		(end 87.473282 -235.285788)
		(width 0.088646)
		(layer "In4.Cu")
		(net "M_B_CPU1_SB_DQS_DN<0>")
	)
	(segment
		(start 62.505082 -226.901756)
		(end 62.244986 -226.64166)
		(width 0.18288)
		(layer "In4.Cu")
		(net "M_B_CPU1_SB_DQS_DN<0>")
	)
	(segment
		(start 71.925434 -232.762806)
		(end 71.537322 -232.374694)
		(width 0.18288)
		(layer "In4.Cu")
		(net "M_B_CPU1_SB_DQS_DN<0>")
	)
	(segment
		(start 68.681346 -229.518718)
		(end 68.505324 -229.518718)
		(width 0.18288)
		(layer "In4.Cu")
		(net "M_B_CPU1_SB_DQS_DN<0>")
	)
	(segment
		(start 50.266092 -228.645974)
		(end 49.565306 -227.945188)
		(width 0.18288)
		(layer "In4.Cu")
		(net "M_B_CPU1_SB_DQS_DN<0>")
	)
	(segment
		(start 70.02145 -230.858822)
		(end 69.633338 -230.47071)
		(width 0.18288)
		(layer "In4.Cu")
		(net "M_B_CPU1_SB_DQS_DN<0>")
	)
	(segment
		(start 57.041796 -227.846636)
		(end 56.258714 -227.846636)
		(width 0.18288)
		(layer "In4.Cu")
		(net "M_B_CPU1_SB_DQS_DN<0>")
	)
	(segment
		(start 70.973442 -231.810814)
		(end 70.58533 -231.422702)
		(width 0.18288)
		(layer "In4.Cu")
		(net "M_B_CPU1_SB_DQS_DN<0>")
	)
	(segment
		(start 67.5767 -228.590094)
		(end 66.59245 -228.590094)
		(width 0.18288)
		(layer "In4.Cu")
		(net "M_B_CPU1_SB_DQS_DN<0>")
	)
	(segment
		(start 65.203578 -228.587554)
		(end 64.81572 -228.199696)
		(width 0.18288)
		(layer "In4.Cu")
		(net "M_B_CPU1_SB_DQS_DN<0>")
	)
	(segment
		(start 69.069458 -229.90683)
		(end 68.681346 -229.518718)
		(width 0.18288)
		(layer "In4.Cu")
		(net "M_B_CPU1_SB_DQS_DN<0>")
	)
	(segment
		(start 65.68313 -228.587554)
		(end 65.203578 -228.587554)
		(width 0.18288)
		(layer "In4.Cu")
		(net "M_B_CPU1_SB_DQS_DN<0>")
	)
	(segment
		(start 70.58533 -231.422702)
		(end 70.409308 -231.422702)
		(width 0.18288)
		(layer "In4.Cu")
		(net "M_B_CPU1_SB_DQS_DN<0>")
	)
	(segment
		(start 54.239414 -227.722176)
		(end 54.114954 -227.846636)
		(width 0.18288)
		(layer "In4.Cu")
		(net "M_B_CPU1_SB_DQS_DN<0>")
	)
	(segment
		(start 90.935556 -235.148882)
		(end 90.682318 -235.294678)
		(width 0.088646)
		(layer "In4.Cu")
		(net "M_B_CPU1_SB_DQS_DN<0>")
	)
	(segment
		(start 73.829418 -234.66679)
		(end 73.441306 -234.278678)
		(width 0.18288)
		(layer "In4.Cu")
		(net "M_B_CPU1_SB_DQS_DN<0>")
	)
	(segment
		(start 56.134254 -227.722176)
		(end 55.585614 -227.722176)
		(width 0.18288)
		(layer "In4.Cu")
		(net "M_B_CPU1_SB_DQS_DN<0>")
	)
	(segment
		(start 73.829418 -234.842812)
		(end 73.829418 -234.66679)
		(width 0.18288)
		(layer "In4.Cu")
		(net "M_B_CPU1_SB_DQS_DN<0>")
	)
	(segment
		(start 61.853064 -226.64166)
		(end 61.587634 -226.90709)
		(width 0.18288)
		(layer "In4.Cu")
		(net "M_B_CPU1_SB_DQS_DN<0>")
	)
	(segment
		(start 57.429654 -227.458778)
		(end 57.041796 -227.846636)
		(width 0.18288)
		(layer "In4.Cu")
		(net "M_B_CPU1_SB_DQS_DN<0>")
	)
	(segment
		(start 63.51778 -226.901756)
		(end 62.505082 -226.901756)
		(width 0.18288)
		(layer "In4.Cu")
		(net "M_B_CPU1_SB_DQS_DN<0>")
	)
	(segment
		(start 69.633338 -230.47071)
		(end 69.457316 -230.47071)
		(width 0.18288)
		(layer "In4.Cu")
		(net "M_B_CPU1_SB_DQS_DN<0>")
	)
	(segment
		(start 53.071268 -228.341682)
		(end 50.841402 -228.341682)
		(width 0.18288)
		(layer "In4.Cu")
		(net "M_B_CPU1_SB_DQS_DN<0>")
	)
	(segment
		(start 64.427608 -227.635562)
		(end 64.251586 -227.635562)
		(width 0.18288)
		(layer "In4.Cu")
		(net "M_B_CPU1_SB_DQS_DN<0>")
	)
	(segment
		(start 61.587634 -226.90709)
		(end 61.165486 -226.90709)
		(width 0.18288)
		(layer "In4.Cu")
		(net "M_B_CPU1_SB_DQS_DN<0>")
	)
	(segment
		(start 48.220122 -227.945188)
		(end 47.671482 -227.945188)
		(width 0.18288)
		(layer "In4.Cu")
		(net "M_B_CPU1_SB_DQS_DN<0>")
	)
	(segment
		(start 58.805064 -226.648264)
		(end 58.240168 -226.648264)
		(width 0.18288)
		(layer "In4.Cu")
		(net "M_B_CPU1_SB_DQS_DN<0>")
	)
	(segment
		(start 72.877426 -233.89082)
		(end 72.877426 -233.714798)
		(width 0.18288)
		(layer "In4.Cu")
		(net "M_B_CPU1_SB_DQS_DN<0>")
	)
	(segment
		(start 47.671482 -227.945188)
		(end 47.441358 -228.175312)
		(width 0.18288)
		(layer "In4.Cu")
		(net "M_B_CPU1_SB_DQS_DN<0>")
	)
	(segment
		(start 54.788054 -227.722176)
		(end 54.239414 -227.722176)
		(width 0.18288)
		(layer "In4.Cu")
		(net "M_B_CPU1_SB_DQS_DN<0>")
	)
	(segment
		(start 47.441358 -228.175312)
		(end 47.222918 -228.175312)
		(width 0.18288)
		(layer "In4.Cu")
		(net "M_B_CPU1_SB_DQS_DN<0>")
	)
	(segment
		(start 58.240168 -226.648264)
		(end 57.993788 -226.894644)
		(width 0.18288)
		(layer "In4.Cu")
		(net "M_B_CPU1_SB_DQS_DN<0>")
	)
	(segment
		(start 64.81572 -228.199696)
		(end 64.81572 -228.023674)
		(width 0.18288)
		(layer "In4.Cu")
		(net "M_B_CPU1_SB_DQS_DN<0>")
	)
	(segment
		(start 71.925434 -232.938828)
		(end 71.925434 -232.762806)
		(width 0.18288)
		(layer "In4.Cu")
		(net "M_B_CPU1_SB_DQS_DN<0>")
	)
	(segment
		(start 90.307668 -235.294424)
		(end 90.297254 -235.288328)
		(width 0.088646)
		(layer "In4.Cu")
		(net "M_B_CPU1_SB_DQS_DN<0>")
	)
	(segment
		(start 49.017682 -227.945188)
		(end 48.893222 -227.820728)
		(width 0.18288)
		(layer "In4.Cu")
		(net "M_B_CPU1_SB_DQS_DN<0>")
	)
	(segment
		(start 84.151724 -235.218732)
		(end 84.080096 -235.29036)
		(width 0.088646)
		(layer "In4.Cu")
		(net "M_B_CPU1_SB_DQS_DN<0>")
	)
	(segment
		(start 73.265284 -234.278678)
		(end 72.877426 -233.89082)
		(width 0.18288)
		(layer "In4.Cu")
		(net "M_B_CPU1_SB_DQS_DN<0>")
	)
	(segment
		(start 66.347086 -228.34473)
		(end 65.925954 -228.34473)
		(width 0.18288)
		(layer "In4.Cu")
		(net "M_B_CPU1_SB_DQS_DN<0>")
	)
	(segment
		(start 74.217276 -235.23067)
		(end 73.829418 -234.842812)
		(width 0.18288)
		(layer "In4.Cu")
		(net "M_B_CPU1_SB_DQS_DN<0>")
	)
	(segment
		(start 50.53711 -228.645974)
		(end 50.266092 -228.645974)
		(width 0.18288)
		(layer "In4.Cu")
		(net "M_B_CPU1_SB_DQS_DN<0>")
	)
	(segment
		(start 61.165486 -226.90709)
		(end 60.518294 -226.259898)
		(width 0.18288)
		(layer "In4.Cu")
		(net "M_B_CPU1_SB_DQS_DN<0>")
	)
	(segment
		(start 85.608414 -235.294424)
		(end 85.593682 -235.285788)
		(width 0.088646)
		(layer "In4.Cu")
		(net "M_B_CPU1_SB_DQS_DN<0>")
	)
	(segment
		(start 70.973442 -231.986836)
		(end 70.973442 -231.810814)
		(width 0.18288)
		(layer "In4.Cu")
		(net "M_B_CPU1_SB_DQS_DN<0>")
	)
	(segment
		(start 54.912514 -227.846636)
		(end 54.788054 -227.722176)
		(width 0.18288)
		(layer "In4.Cu")
		(net "M_B_CPU1_SB_DQS_DN<0>")
	)
	(segment
		(start 82.708496 -235.23067)
		(end 74.217276 -235.23067)
		(width 0.18288)
		(layer "In4.Cu")
		(net "M_B_CPU1_SB_DQS_DN<0>")
	)
	(segment
		(start 48.344582 -227.820728)
		(end 48.220122 -227.945188)
		(width 0.18288)
		(layer "In4.Cu")
		(net "M_B_CPU1_SB_DQS_DN<0>")
	)
	(segment
		(start 73.441306 -234.278678)
		(end 73.265284 -234.278678)
		(width 0.18288)
		(layer "In4.Cu")
		(net "M_B_CPU1_SB_DQS_DN<0>")
	)
	(segment
		(start 91.209114 -235.148882)
		(end 90.935556 -235.148882)
		(width 0.088646)
		(layer "In4.Cu")
		(net "M_B_CPU1_SB_DQS_DN<0>")
	)
	(segment
		(start 70.409308 -231.422702)
		(end 70.02145 -231.034844)
		(width 0.18288)
		(layer "In4.Cu")
		(net "M_B_CPU1_SB_DQS_DN<0>")
	)
	(segment
		(start 84.385912 -235.218732)
		(end 84.151724 -235.218732)
		(width 0.088646)
		(layer "In4.Cu")
		(net "M_B_CPU1_SB_DQS_DN<0>")
	)
	(segment
		(start 65.925954 -228.34473)
		(end 65.68313 -228.587554)
		(width 0.18288)
		(layer "In4.Cu")
		(net "M_B_CPU1_SB_DQS_DN<0>")
	)
	(segment
		(start 86.548214 -235.294424)
		(end 86.533482 -235.285788)
		(width 0.088646)
		(layer "In4.Cu")
		(net "M_B_CPU1_SB_DQS_DN<0>")
	)
	(segment
		(start 47.222918 -228.175312)
		(end 46.964346 -227.91674)
		(width 0.18288)
		(layer "In4.Cu")
		(net "M_B_CPU1_SB_DQS_DN<0>")
	)
	(segment
		(start 62.244986 -226.64166)
		(end 61.853064 -226.64166)
		(width 0.18288)
		(layer "In4.Cu")
		(net "M_B_CPU1_SB_DQS_DN<0>")
	)
	(segment
		(start 49.565306 -227.945188)
		(end 49.017682 -227.945188)
		(width 0.18288)
		(layer "In4.Cu")
		(net "M_B_CPU1_SB_DQS_DN<0>")
	)
	(segment
		(start 90.682318 -235.294678)
		(end 90.682064 -235.294424)
		(width 0.088646)
		(layer "In4.Cu")
		(net "M_B_CPU1_SB_DQS_DN<0>")
	)
	(segment
		(start 70.02145 -231.034844)
		(end 70.02145 -230.858822)
		(width 0.18288)
		(layer "In4.Cu")
		(net "M_B_CPU1_SB_DQS_DN<0>")
	)
	(segment
		(start 54.114954 -227.846636)
		(end 53.566314 -227.846636)
		(width 0.18288)
		(layer "In4.Cu")
		(net "M_B_CPU1_SB_DQS_DN<0>")
	)
	(segment
		(start 71.537322 -232.374694)
		(end 71.3613 -232.374694)
		(width 0.18288)
		(layer "In4.Cu")
		(net "M_B_CPU1_SB_DQS_DN<0>")
	)
	(segment
		(start 82.806286 -235.29036)
		(end 82.746596 -235.23067)
		(width 0.088646)
		(layer "In4.Cu")
		(net "M_B_CPU1_SB_DQS_DN<0>")
	)
	(segment
		(start 84.080096 -235.29036)
		(end 82.806286 -235.29036)
		(width 0.088646)
		(layer "In4.Cu")
		(net "M_B_CPU1_SB_DQS_DN<0>")
	)
	(segment
		(start 72.877426 -233.714798)
		(end 72.489314 -233.326686)
		(width 0.18288)
		(layer "In4.Cu")
		(net "M_B_CPU1_SB_DQS_DN<0>")
	)
	(segment
		(start 71.3613 -232.374694)
		(end 70.973442 -231.986836)
		(width 0.18288)
		(layer "In4.Cu")
		(net "M_B_CPU1_SB_DQS_DN<0>")
	)
	(segment
		(start 69.069458 -230.082852)
		(end 69.069458 -229.90683)
		(width 0.18288)
		(layer "In4.Cu")
		(net "M_B_CPU1_SB_DQS_DN<0>")
	)
	(arc
		(start 89.74201 -235.294424)
		(mid 89.554812 -235.344567)
		(end 89.367614 -235.294424)
		(width 0.088646)
		(layer "In4.Cu")
		(net "M_B_CPU1_SB_DQS_DN<0>")
	)
	(arc
		(start 88.413082 -235.285788)
		(mid 88.136607 -235.218468)
		(end 87.86241 -235.294424)
		(width 0.088646)
		(layer "In4.Cu")
		(net "M_B_CPU1_SB_DQS_DN<0>")
	)
	(arc
		(start 90.682064 -235.294424)
		(mid 90.494866 -235.344567)
		(end 90.307668 -235.294424)
		(width 0.088646)
		(layer "In4.Cu")
		(net "M_B_CPU1_SB_DQS_DN<0>")
	)
	(arc
		(start 90.297254 -235.288328)
		(mid 90.018822 -235.218482)
		(end 89.74201 -235.294424)
		(width 0.088646)
		(layer "In4.Cu")
		(net "M_B_CPU1_SB_DQS_DN<0>")
	)
	(arc
		(start 85.98281 -235.294424)
		(mid 85.795612 -235.344567)
		(end 85.608414 -235.294424)
		(width 0.088646)
		(layer "In4.Cu")
		(net "M_B_CPU1_SB_DQS_DN<0>")
	)
	(arc
		(start 86.92261 -235.294424)
		(mid 86.735412 -235.344567)
		(end 86.548214 -235.294424)
		(width 0.088646)
		(layer "In4.Cu")
		(net "M_B_CPU1_SB_DQS_DN<0>")
	)
	(arc
		(start 85.593682 -235.285788)
		(mid 85.317207 -235.218468)
		(end 85.04301 -235.294424)
		(width 0.088646)
		(layer "In4.Cu")
		(net "M_B_CPU1_SB_DQS_DN<0>")
	)
	(arc
		(start 86.533482 -235.285788)
		(mid 86.257007 -235.218468)
		(end 85.98281 -235.294424)
		(width 0.088646)
		(layer "In4.Cu")
		(net "M_B_CPU1_SB_DQS_DN<0>")
	)
	(arc
		(start 87.86241 -235.294424)
		(mid 87.675212 -235.344567)
		(end 87.488014 -235.294424)
		(width 0.088646)
		(layer "In4.Cu")
		(net "M_B_CPU1_SB_DQS_DN<0>")
	)
	(arc
		(start 85.04301 -235.294424)
		(mid 84.855812 -235.344567)
		(end 84.668614 -235.294424)
		(width 0.088646)
		(layer "In4.Cu")
		(net "M_B_CPU1_SB_DQS_DN<0>")
	)
	(arc
		(start 91.3638 -235.107988)
		(mid 91.289115 -235.138493)
		(end 91.209114 -235.148882)
		(width 0.088646)
		(layer "In4.Cu")
		(net "M_B_CPU1_SB_DQS_DN<0>")
	)
	(arc
		(start 89.352882 -235.285788)
		(mid 89.076407 -235.218468)
		(end 88.80221 -235.294424)
		(width 0.088646)
		(layer "In4.Cu")
		(net "M_B_CPU1_SB_DQS_DN<0>")
	)
	(arc
		(start 87.473282 -235.285788)
		(mid 87.196807 -235.218468)
		(end 86.92261 -235.294424)
		(width 0.088646)
		(layer "In4.Cu")
		(net "M_B_CPU1_SB_DQS_DN<0>")
	)
	(arc
		(start 88.80221 -235.294424)
		(mid 88.615012 -235.344567)
		(end 88.427814 -235.294424)
		(width 0.088646)
		(layer "In4.Cu")
		(net "M_B_CPU1_SB_DQS_DN<0>")
	)
	(arc
		(start 84.668614 -235.294424)
		(mid 84.532244 -235.237971)
		(end 84.385912 -235.218732)
		(width 0.088646)
		(layer "In4.Cu")
		(net "M_B_CPU1_SB_DQS_DN<0>")
	)
	(segment
		(start 40.520112 -221.173548)
		(end 40.36568 -221.32798)
		(width 0.20066)
		(layer "F.Cu")
		(net "M_B_CPU1_SB_DQ<9>")
	)
	(segment
		(start 40.682672 -220.68282)
		(end 40.520112 -220.84538)
		(width 0.20066)
		(layer "F.Cu")
		(net "M_B_CPU1_SB_DQ<9>")
	)
	(segment
		(start 41.29151 -220.68282)
		(end 40.682672 -220.68282)
		(width 0.20066)
		(layer "F.Cu")
		(net "M_B_CPU1_SB_DQ<9>")
	)
	(segment
		(start 44.22013 -221.116652)
		(end 43.795188 -220.69171)
		(width 0.20066)
		(layer "F.Cu")
		(net "M_B_CPU1_SB_DQ<9>")
	)
	(segment
		(start 39.861236 -221.32798)
		(end 39.649908 -221.116652)
		(width 0.20066)
		(layer "F.Cu")
		(net "M_B_CPU1_SB_DQ<9>")
	)
	(segment
		(start 88.615012 -233.877866)
		(end 88.615012 -233.34218)
		(width 0.20066)
		(layer "F.Cu")
		(net "M_B_CPU1_SB_DQ<9>")
	)
	(segment
		(start 88.615266 -233.87812)
		(end 88.615012 -233.877866)
		(width 0.20066)
		(layer "F.Cu")
		(net "M_B_CPU1_SB_DQ<9>")
	)
	(segment
		(start 43.616626 -220.69171)
		(end 43.285918 -220.69171)
		(width 0.101854)
		(layer "F.Cu")
		(net "M_B_CPU1_SB_DQ<9>")
	)
	(segment
		(start 43.795188 -220.69171)
		(end 43.616626 -220.69171)
		(width 0.20066)
		(layer "F.Cu")
		(net "M_B_CPU1_SB_DQ<9>")
	)
	(segment
		(start 43.285918 -220.69171)
		(end 41.3004 -220.69171)
		(width 0.1016)
		(layer "F.Cu")
		(net "M_B_CPU1_SB_DQ<9>")
	)
	(segment
		(start 40.520112 -220.84538)
		(end 40.520112 -221.173548)
		(width 0.20066)
		(layer "F.Cu")
		(net "M_B_CPU1_SB_DQ<9>")
	)
	(segment
		(start 41.3004 -220.69171)
		(end 41.29151 -220.68282)
		(width 0.1016)
		(layer "F.Cu")
		(net "M_B_CPU1_SB_DQ<9>")
	)
	(segment
		(start 46.964346 -221.116652)
		(end 45.859446 -221.116652)
		(width 0.20066)
		(layer "F.Cu")
		(net "M_B_CPU1_SB_DQ<9>")
	)
	(segment
		(start 39.649908 -221.116652)
		(end 38.315646 -221.116652)
		(width 0.20066)
		(layer "F.Cu")
		(net "M_B_CPU1_SB_DQ<9>")
	)
	(segment
		(start 45.859446 -221.116652)
		(end 44.22013 -221.116652)
		(width 0.20066)
		(layer "F.Cu")
		(net "M_B_CPU1_SB_DQ<9>")
	)
	(segment
		(start 40.36568 -221.32798)
		(end 39.861236 -221.32798)
		(width 0.20066)
		(layer "F.Cu")
		(net "M_B_CPU1_SB_DQ<9>")
	)
	(segment
		(start 54.985158 -221.369382)
		(end 54.34584 -221.369382)
		(width 0.18288)
		(layer "In2.Cu")
		(net "M_B_CPU1_SB_DQ<9>")
	)
	(segment
		(start 59.782964 -221.49562)
		(end 58.930794 -222.34779)
		(width 0.18288)
		(layer "In2.Cu")
		(net "M_B_CPU1_SB_DQ<9>")
	)
	(segment
		(start 84.386166 -233.781092)
		(end 83.795616 -233.781092)
		(width 0.088646)
		(layer "In2.Cu")
		(net "M_B_CPU1_SB_DQ<9>")
	)
	(segment
		(start 52.4256 -221.412054)
		(end 51.509422 -221.412054)
		(width 0.18288)
		(layer "In2.Cu")
		(net "M_B_CPU1_SB_DQ<9>")
	)
	(segment
		(start 82.655918 -233.538776)
		(end 70.13194 -221.014798)
		(width 0.18288)
		(layer "In2.Cu")
		(net "M_B_CPU1_SB_DQ<9>")
	)
	(segment
		(start 48.484282 -221.751652)
		(end 48.484282 -222.245174)
		(width 0.18288)
		(layer "In2.Cu")
		(net "M_B_CPU1_SB_DQ<9>")
	)
	(segment
		(start 50.455068 -221.347792)
		(end 50.455068 -220.908372)
		(width 0.18288)
		(layer "In2.Cu")
		(net "M_B_CPU1_SB_DQ<9>")
	)
	(segment
		(start 69.379338 -221.494096)
		(end 67.154552 -221.494096)
		(width 0.18288)
		(layer "In2.Cu")
		(net "M_B_CPU1_SB_DQ<9>")
	)
	(segment
		(start 58.930794 -222.34779)
		(end 55.963566 -222.34779)
		(width 0.18288)
		(layer "In2.Cu")
		(net "M_B_CPU1_SB_DQ<9>")
	)
	(segment
		(start 47.606712 -221.309946)
		(end 47.413418 -221.116652)
		(width 0.18288)
		(layer "In2.Cu")
		(net "M_B_CPU1_SB_DQ<9>")
	)
	(segment
		(start 62.493144 -221.49562)
		(end 59.782964 -221.49562)
		(width 0.18288)
		(layer "In2.Cu")
		(net "M_B_CPU1_SB_DQ<9>")
	)
	(segment
		(start 83.5533 -233.538776)
		(end 83.241896 -233.538776)
		(width 0.088646)
		(layer "In2.Cu")
		(net "M_B_CPU1_SB_DQ<9>")
	)
	(segment
		(start 47.800006 -222.438468)
		(end 47.606712 -222.245174)
		(width 0.18288)
		(layer "In2.Cu")
		(net "M_B_CPU1_SB_DQ<9>")
	)
	(segment
		(start 67.154552 -221.494096)
		(end 66.332608 -220.672152)
		(width 0.18288)
		(layer "In2.Cu")
		(net "M_B_CPU1_SB_DQ<9>")
	)
	(segment
		(start 85.138514 -233.831892)
		(end 85.138768 -233.831892)
		(width 0.088646)
		(layer "In2.Cu")
		(net "M_B_CPU1_SB_DQ<9>")
	)
	(segment
		(start 48.484282 -222.245174)
		(end 48.290988 -222.438468)
		(width 0.18288)
		(layer "In2.Cu")
		(net "M_B_CPU1_SB_DQ<9>")
	)
	(segment
		(start 70.13194 -221.014798)
		(end 69.858636 -221.014798)
		(width 0.18288)
		(layer "In2.Cu")
		(net "M_B_CPU1_SB_DQ<9>")
	)
	(segment
		(start 86.078568 -233.831892)
		(end 86.068154 -233.837988)
		(width 0.088646)
		(layer "In2.Cu")
		(net "M_B_CPU1_SB_DQ<9>")
	)
	(segment
		(start 50.295048 -220.748352)
		(end 49.741582 -220.748352)
		(width 0.18288)
		(layer "In2.Cu")
		(net "M_B_CPU1_SB_DQ<9>")
	)
	(segment
		(start 63.316612 -220.672152)
		(end 62.493144 -221.49562)
		(width 0.18288)
		(layer "In2.Cu")
		(net "M_B_CPU1_SB_DQ<9>")
	)
	(segment
		(start 51.379628 -221.541848)
		(end 50.649124 -221.541848)
		(width 0.18288)
		(layer "In2.Cu")
		(net "M_B_CPU1_SB_DQ<9>")
	)
	(segment
		(start 50.455068 -220.908372)
		(end 50.295048 -220.748352)
		(width 0.18288)
		(layer "In2.Cu")
		(net "M_B_CPU1_SB_DQ<9>")
	)
	(segment
		(start 88.030304 -233.789982)
		(end 87.958168 -233.831892)
		(width 0.088646)
		(layer "In2.Cu")
		(net "M_B_CPU1_SB_DQ<9>")
	)
	(segment
		(start 47.413418 -221.116652)
		(end 46.964346 -221.116652)
		(width 0.18288)
		(layer "In2.Cu")
		(net "M_B_CPU1_SB_DQ<9>")
	)
	(segment
		(start 69.858636 -221.014798)
		(end 69.379338 -221.494096)
		(width 0.18288)
		(layer "In2.Cu")
		(net "M_B_CPU1_SB_DQ<9>")
	)
	(segment
		(start 83.241896 -233.538776)
		(end 82.655918 -233.538776)
		(width 0.18288)
		(layer "In2.Cu")
		(net "M_B_CPU1_SB_DQ<9>")
	)
	(segment
		(start 48.290988 -222.438468)
		(end 47.800006 -222.438468)
		(width 0.18288)
		(layer "In2.Cu")
		(net "M_B_CPU1_SB_DQ<9>")
	)
	(segment
		(start 49.741582 -220.748352)
		(end 49.581562 -220.908372)
		(width 0.18288)
		(layer "In2.Cu")
		(net "M_B_CPU1_SB_DQ<9>")
	)
	(segment
		(start 54.137814 -221.577408)
		(end 52.590954 -221.577408)
		(width 0.18288)
		(layer "In2.Cu")
		(net "M_B_CPU1_SB_DQ<9>")
	)
	(segment
		(start 50.649124 -221.541848)
		(end 50.455068 -221.347792)
		(width 0.18288)
		(layer "In2.Cu")
		(net "M_B_CPU1_SB_DQ<9>")
	)
	(segment
		(start 51.509422 -221.412054)
		(end 51.379628 -221.541848)
		(width 0.18288)
		(layer "In2.Cu")
		(net "M_B_CPU1_SB_DQ<9>")
	)
	(segment
		(start 88.615012 -233.34218)
		(end 88.614758 -233.342434)
		(width 0.088646)
		(layer "In2.Cu")
		(net "M_B_CPU1_SB_DQ<9>")
	)
	(segment
		(start 55.963566 -222.34779)
		(end 54.985158 -221.369382)
		(width 0.18288)
		(layer "In2.Cu")
		(net "M_B_CPU1_SB_DQ<9>")
	)
	(segment
		(start 52.590954 -221.577408)
		(end 52.4256 -221.412054)
		(width 0.18288)
		(layer "In2.Cu")
		(net "M_B_CPU1_SB_DQ<9>")
	)
	(segment
		(start 47.606712 -222.245174)
		(end 47.606712 -221.309946)
		(width 0.18288)
		(layer "In2.Cu")
		(net "M_B_CPU1_SB_DQ<9>")
	)
	(segment
		(start 54.34584 -221.369382)
		(end 54.137814 -221.577408)
		(width 0.18288)
		(layer "In2.Cu")
		(net "M_B_CPU1_SB_DQ<9>")
	)
	(segment
		(start 48.677322 -221.558612)
		(end 48.484282 -221.751652)
		(width 0.18288)
		(layer "In2.Cu")
		(net "M_B_CPU1_SB_DQ<9>")
	)
	(segment
		(start 49.403508 -221.558612)
		(end 48.677322 -221.558612)
		(width 0.18288)
		(layer "In2.Cu")
		(net "M_B_CPU1_SB_DQ<9>")
	)
	(segment
		(start 49.581562 -220.908372)
		(end 49.581562 -221.380558)
		(width 0.18288)
		(layer "In2.Cu")
		(net "M_B_CPU1_SB_DQ<9>")
	)
	(segment
		(start 66.332608 -220.672152)
		(end 63.316612 -220.672152)
		(width 0.18288)
		(layer "In2.Cu")
		(net "M_B_CPU1_SB_DQ<9>")
	)
	(segment
		(start 49.581562 -221.380558)
		(end 49.403508 -221.558612)
		(width 0.18288)
		(layer "In2.Cu")
		(net "M_B_CPU1_SB_DQ<9>")
	)
	(segment
		(start 83.795616 -233.781092)
		(end 83.5533 -233.538776)
		(width 0.088646)
		(layer "In2.Cu")
		(net "M_B_CPU1_SB_DQ<9>")
	)
	(arc
		(start 86.452964 -233.831892)
		(mid 86.265766 -233.781749)
		(end 86.078568 -233.831892)
		(width 0.088646)
		(layer "In2.Cu")
		(net "M_B_CPU1_SB_DQ<9>")
	)
	(arc
		(start 85.51291 -233.831892)
		(mid 85.325712 -233.781749)
		(end 85.138514 -233.831892)
		(width 0.088646)
		(layer "In2.Cu")
		(net "M_B_CPU1_SB_DQ<9>")
	)
	(arc
		(start 87.958168 -233.831892)
		(mid 87.675466 -233.907634)
		(end 87.392764 -233.831892)
		(width 0.088646)
		(layer "In2.Cu")
		(net "M_B_CPU1_SB_DQ<9>")
	)
	(arc
		(start 87.018368 -233.831892)
		(mid 86.735666 -233.907634)
		(end 86.452964 -233.831892)
		(width 0.088646)
		(layer "In2.Cu")
		(net "M_B_CPU1_SB_DQ<9>")
	)
	(arc
		(start 85.138768 -233.831892)
		(mid 84.856066 -233.907634)
		(end 84.573364 -233.831892)
		(width 0.088646)
		(layer "In2.Cu")
		(net "M_B_CPU1_SB_DQ<9>")
	)
	(arc
		(start 87.392764 -233.831892)
		(mid 87.205566 -233.781749)
		(end 87.018368 -233.831892)
		(width 0.088646)
		(layer "In2.Cu")
		(net "M_B_CPU1_SB_DQ<9>")
	)
	(arc
		(start 86.068154 -233.837988)
		(mid 85.789722 -233.907802)
		(end 85.51291 -233.831892)
		(width 0.088646)
		(layer "In2.Cu")
		(net "M_B_CPU1_SB_DQ<9>")
	)
	(arc
		(start 88.614758 -233.342434)
		(mid 88.337327 -233.585531)
		(end 88.030304 -233.789982)
		(width 0.088646)
		(layer "In2.Cu")
		(net "M_B_CPU1_SB_DQ<9>")
	)
	(arc
		(start 84.573364 -233.831892)
		(mid 84.483108 -233.79417)
		(end 84.386166 -233.781092)
		(width 0.088646)
		(layer "In2.Cu")
		(net "M_B_CPU1_SB_DQ<9>")
	)
	(segment
		(start 40.520112 -222.882714)
		(end 40.347392 -223.055434)
		(width 0.20066)
		(layer "F.Cu")
		(net "M_B_CPU1_SB_DQ<8>")
	)
	(segment
		(start 46.964346 -222.816674)
		(end 45.859446 -222.816674)
		(width 0.20066)
		(layer "F.Cu")
		(net "M_B_CPU1_SB_DQ<8>")
	)
	(segment
		(start 39.888668 -223.055434)
		(end 39.649908 -222.816674)
		(width 0.20066)
		(layer "F.Cu")
		(net "M_B_CPU1_SB_DQ<8>")
	)
	(segment
		(start 40.347392 -223.055434)
		(end 39.888668 -223.055434)
		(width 0.20066)
		(layer "F.Cu")
		(net "M_B_CPU1_SB_DQ<8>")
	)
	(segment
		(start 44.490386 -222.816674)
		(end 44.065444 -222.391732)
		(width 0.20066)
		(layer "F.Cu")
		(net "M_B_CPU1_SB_DQ<8>")
	)
	(segment
		(start 39.649908 -222.816674)
		(end 38.315646 -222.816674)
		(width 0.20066)
		(layer "F.Cu")
		(net "M_B_CPU1_SB_DQ<8>")
	)
	(segment
		(start 40.520112 -222.593154)
		(end 40.520112 -222.882714)
		(width 0.20066)
		(layer "F.Cu")
		(net "M_B_CPU1_SB_DQ<8>")
	)
	(segment
		(start 43.616626 -222.391732)
		(end 41.547542 -222.391732)
		(width 0.1016)
		(layer "F.Cu")
		(net "M_B_CPU1_SB_DQ<8>")
	)
	(segment
		(start 89.084912 -234.156504)
		(end 89.085166 -234.15625)
		(width 0.20066)
		(layer "F.Cu")
		(net "M_B_CPU1_SB_DQ<8>")
	)
	(segment
		(start 40.729662 -222.383604)
		(end 40.520112 -222.593154)
		(width 0.20066)
		(layer "F.Cu")
		(net "M_B_CPU1_SB_DQ<8>")
	)
	(segment
		(start 41.29151 -222.383604)
		(end 40.729662 -222.383604)
		(width 0.20066)
		(layer "F.Cu")
		(net "M_B_CPU1_SB_DQ<8>")
	)
	(segment
		(start 41.299638 -222.391732)
		(end 41.29151 -222.383604)
		(width 0.101854)
		(layer "F.Cu")
		(net "M_B_CPU1_SB_DQ<8>")
	)
	(segment
		(start 45.859446 -222.816674)
		(end 44.490386 -222.816674)
		(width 0.20066)
		(layer "F.Cu")
		(net "M_B_CPU1_SB_DQ<8>")
	)
	(segment
		(start 41.547542 -222.391732)
		(end 41.299638 -222.391732)
		(width 0.101854)
		(layer "F.Cu")
		(net "M_B_CPU1_SB_DQ<8>")
	)
	(segment
		(start 44.065444 -222.391732)
		(end 43.616626 -222.391732)
		(width 0.20066)
		(layer "F.Cu")
		(net "M_B_CPU1_SB_DQ<8>")
	)
	(segment
		(start 89.084912 -234.69219)
		(end 89.084912 -234.156504)
		(width 0.20066)
		(layer "F.Cu")
		(net "M_B_CPU1_SB_DQ<8>")
	)
	(segment
		(start 58.170572 -224.228406)
		(end 58.170572 -224.681034)
		(width 0.18288)
		(layer "In2.Cu")
		(net "M_B_CPU1_SB_DQ<8>")
	)
	(segment
		(start 51.411632 -223.197166)
		(end 51.367182 -223.241616)
		(width 0.18288)
		(layer "In2.Cu")
		(net "M_B_CPU1_SB_DQ<8>")
	)
	(segment
		(start 53.10632 -223.73844)
		(end 53.10632 -223.428052)
		(width 0.18288)
		(layer "In2.Cu")
		(net "M_B_CPU1_SB_DQ<8>")
	)
	(segment
		(start 47.514002 -224.130616)
		(end 47.514002 -223.36633)
		(width 0.18288)
		(layer "In2.Cu")
		(net "M_B_CPU1_SB_DQ<8>")
	)
	(segment
		(start 87.488014 -234.645708)
		(end 87.473282 -234.654344)
		(width 0.088646)
		(layer "In2.Cu")
		(net "M_B_CPU1_SB_DQ<8>")
	)
	(segment
		(start 53.10632 -223.428052)
		(end 52.875434 -223.197166)
		(width 0.18288)
		(layer "In2.Cu")
		(net "M_B_CPU1_SB_DQ<8>")
	)
	(segment
		(start 48.976026 -223.241616)
		(end 48.467518 -223.750124)
		(width 0.18288)
		(layer "In2.Cu")
		(net "M_B_CPU1_SB_DQ<8>")
	)
	(segment
		(start 47.759366 -224.37598)
		(end 47.514002 -224.130616)
		(width 0.18288)
		(layer "In2.Cu")
		(net "M_B_CPU1_SB_DQ<8>")
	)
	(segment
		(start 60.080144 -224.09912)
		(end 59.59856 -224.09912)
		(width 0.18288)
		(layer "In2.Cu")
		(net "M_B_CPU1_SB_DQ<8>")
	)
	(segment
		(start 70.231 -222.574612)
		(end 66.549778 -222.574612)
		(width 0.18288)
		(layer "In2.Cu")
		(net "M_B_CPU1_SB_DQ<8>")
	)
	(segment
		(start 60.984892 -223.194372)
		(end 60.080144 -224.09912)
		(width 0.18288)
		(layer "In2.Cu")
		(net "M_B_CPU1_SB_DQ<8>")
	)
	(segment
		(start 54.208934 -224.048574)
		(end 53.416454 -224.048574)
		(width 0.18288)
		(layer "In2.Cu")
		(net "M_B_CPU1_SB_DQ<8>")
	)
	(segment
		(start 53.416454 -224.048574)
		(end 53.10632 -223.73844)
		(width 0.18288)
		(layer "In2.Cu")
		(net "M_B_CPU1_SB_DQ<8>")
	)
	(segment
		(start 58.375042 -224.023936)
		(end 58.170572 -224.228406)
		(width 0.18288)
		(layer "In2.Cu")
		(net "M_B_CPU1_SB_DQ<8>")
	)
	(segment
		(start 55.12308 -224.96272)
		(end 54.208934 -224.048574)
		(width 0.18288)
		(layer "In2.Cu")
		(net "M_B_CPU1_SB_DQ<8>")
	)
	(segment
		(start 66.549778 -222.574612)
		(end 66.341498 -222.366332)
		(width 0.18288)
		(layer "In2.Cu")
		(net "M_B_CPU1_SB_DQ<8>")
	)
	(segment
		(start 47.514002 -223.36633)
		(end 46.964346 -222.816674)
		(width 0.18288)
		(layer "In2.Cu")
		(net "M_B_CPU1_SB_DQ<8>")
	)
	(segment
		(start 82.211418 -234.55503)
		(end 70.231 -222.574612)
		(width 0.18288)
		(layer "In2.Cu")
		(net "M_B_CPU1_SB_DQ<8>")
	)
	(segment
		(start 48.467518 -224.18294)
		(end 48.274478 -224.37598)
		(width 0.18288)
		(layer "In2.Cu")
		(net "M_B_CPU1_SB_DQ<8>")
	)
	(segment
		(start 88.427814 -234.645708)
		(end 88.413082 -234.654344)
		(width 0.088646)
		(layer "In2.Cu")
		(net "M_B_CPU1_SB_DQ<8>")
	)
	(segment
		(start 51.367182 -223.241616)
		(end 48.976026 -223.241616)
		(width 0.18288)
		(layer "In2.Cu")
		(net "M_B_CPU1_SB_DQ<8>")
	)
	(segment
		(start 65.05448 -222.366332)
		(end 63.709042 -223.71177)
		(width 0.18288)
		(layer "In2.Cu")
		(net "M_B_CPU1_SB_DQ<8>")
	)
	(segment
		(start 83.766152 -234.594908)
		(end 83.726274 -234.55503)
		(width 0.088646)
		(layer "In2.Cu")
		(net "M_B_CPU1_SB_DQ<8>")
	)
	(segment
		(start 62.770512 -223.71177)
		(end 62.253114 -223.194372)
		(width 0.18288)
		(layer "In2.Cu")
		(net "M_B_CPU1_SB_DQ<8>")
	)
	(segment
		(start 85.608414 -234.645708)
		(end 85.593682 -234.654344)
		(width 0.088646)
		(layer "In2.Cu")
		(net "M_B_CPU1_SB_DQ<8>")
	)
	(segment
		(start 88.46693 -234.623102)
		(end 88.427814 -234.645708)
		(width 0.088646)
		(layer "In2.Cu")
		(net "M_B_CPU1_SB_DQ<8>")
	)
	(segment
		(start 52.875434 -223.197166)
		(end 51.411632 -223.197166)
		(width 0.18288)
		(layer "In2.Cu")
		(net "M_B_CPU1_SB_DQ<8>")
	)
	(segment
		(start 48.274478 -224.37598)
		(end 47.759366 -224.37598)
		(width 0.18288)
		(layer "In2.Cu")
		(net "M_B_CPU1_SB_DQ<8>")
	)
	(segment
		(start 59.523376 -224.023936)
		(end 58.375042 -224.023936)
		(width 0.18288)
		(layer "In2.Cu")
		(net "M_B_CPU1_SB_DQ<8>")
	)
	(segment
		(start 83.241896 -234.55503)
		(end 82.211418 -234.55503)
		(width 0.18288)
		(layer "In2.Cu")
		(net "M_B_CPU1_SB_DQ<8>")
	)
	(segment
		(start 57.888886 -224.96272)
		(end 55.12308 -224.96272)
		(width 0.18288)
		(layer "In2.Cu")
		(net "M_B_CPU1_SB_DQ<8>")
	)
	(segment
		(start 86.548214 -234.645708)
		(end 86.533482 -234.654344)
		(width 0.088646)
		(layer "In2.Cu")
		(net "M_B_CPU1_SB_DQ<8>")
	)
	(segment
		(start 83.726274 -234.55503)
		(end 83.241896 -234.55503)
		(width 0.088646)
		(layer "In2.Cu")
		(net "M_B_CPU1_SB_DQ<8>")
	)
	(segment
		(start 84.668614 -234.645708)
		(end 84.653882 -234.654344)
		(width 0.088646)
		(layer "In2.Cu")
		(net "M_B_CPU1_SB_DQ<8>")
	)
	(segment
		(start 63.709042 -223.71177)
		(end 62.770512 -223.71177)
		(width 0.18288)
		(layer "In2.Cu")
		(net "M_B_CPU1_SB_DQ<8>")
	)
	(segment
		(start 59.59856 -224.09912)
		(end 59.523376 -224.023936)
		(width 0.18288)
		(layer "In2.Cu")
		(net "M_B_CPU1_SB_DQ<8>")
	)
	(segment
		(start 89.085166 -234.15625)
		(end 88.540844 -234.573572)
		(width 0.088646)
		(layer "In2.Cu")
		(net "M_B_CPU1_SB_DQ<8>")
	)
	(segment
		(start 62.253114 -223.194372)
		(end 60.984892 -223.194372)
		(width 0.18288)
		(layer "In2.Cu")
		(net "M_B_CPU1_SB_DQ<8>")
	)
	(segment
		(start 83.916012 -234.594908)
		(end 83.766152 -234.594908)
		(width 0.088646)
		(layer "In2.Cu")
		(net "M_B_CPU1_SB_DQ<8>")
	)
	(segment
		(start 58.170572 -224.681034)
		(end 57.888886 -224.96272)
		(width 0.18288)
		(layer "In2.Cu")
		(net "M_B_CPU1_SB_DQ<8>")
	)
	(segment
		(start 48.467518 -223.750124)
		(end 48.467518 -224.18294)
		(width 0.18288)
		(layer "In2.Cu")
		(net "M_B_CPU1_SB_DQ<8>")
	)
	(segment
		(start 66.341498 -222.366332)
		(end 65.05448 -222.366332)
		(width 0.18288)
		(layer "In2.Cu")
		(net "M_B_CPU1_SB_DQ<8>")
	)
	(arc
		(start 87.86241 -234.645708)
		(mid 87.675212 -234.595565)
		(end 87.488014 -234.645708)
		(width 0.088646)
		(layer "In2.Cu")
		(net "M_B_CPU1_SB_DQ<8>")
	)
	(arc
		(start 88.413082 -234.654344)
		(mid 88.136607 -234.721664)
		(end 87.86241 -234.645708)
		(width 0.088646)
		(layer "In2.Cu")
		(net "M_B_CPU1_SB_DQ<8>")
	)
	(arc
		(start 84.10321 -234.645708)
		(mid 84.012954 -234.607986)
		(end 83.916012 -234.594908)
		(width 0.088646)
		(layer "In2.Cu")
		(net "M_B_CPU1_SB_DQ<8>")
	)
	(arc
		(start 88.540844 -234.573572)
		(mid 88.504688 -234.599533)
		(end 88.46693 -234.623102)
		(width 0.088646)
		(layer "In2.Cu")
		(net "M_B_CPU1_SB_DQ<8>")
	)
	(arc
		(start 85.04301 -234.645708)
		(mid 84.855812 -234.595565)
		(end 84.668614 -234.645708)
		(width 0.088646)
		(layer "In2.Cu")
		(net "M_B_CPU1_SB_DQ<8>")
	)
	(arc
		(start 84.653882 -234.654344)
		(mid 84.377407 -234.721664)
		(end 84.10321 -234.645708)
		(width 0.088646)
		(layer "In2.Cu")
		(net "M_B_CPU1_SB_DQ<8>")
	)
	(arc
		(start 85.593682 -234.654344)
		(mid 85.317207 -234.721664)
		(end 85.04301 -234.645708)
		(width 0.088646)
		(layer "In2.Cu")
		(net "M_B_CPU1_SB_DQ<8>")
	)
	(arc
		(start 86.533482 -234.654344)
		(mid 86.257007 -234.721664)
		(end 85.98281 -234.645708)
		(width 0.088646)
		(layer "In2.Cu")
		(net "M_B_CPU1_SB_DQ<8>")
	)
	(arc
		(start 87.473282 -234.654344)
		(mid 87.196807 -234.721664)
		(end 86.92261 -234.645708)
		(width 0.088646)
		(layer "In2.Cu")
		(net "M_B_CPU1_SB_DQ<8>")
	)
	(arc
		(start 85.98281 -234.645708)
		(mid 85.795612 -234.595565)
		(end 85.608414 -234.645708)
		(width 0.088646)
		(layer "In2.Cu")
		(net "M_B_CPU1_SB_DQ<8>")
	)
	(arc
		(start 86.92261 -234.645708)
		(mid 86.735412 -234.595565)
		(end 86.548214 -234.645708)
		(width 0.088646)
		(layer "In2.Cu")
		(net "M_B_CPU1_SB_DQ<8>")
	)
	(segment
		(start 49.959514 -223.666558)
		(end 49.143412 -223.666558)
		(width 0.20066)
		(layer "F.Cu")
		(net "M_B_CPU1_SB_DQ<7>")
	)
	(segment
		(start 44.238926 -223.96323)
		(end 44.238926 -223.792542)
		(width 0.20066)
		(layer "F.Cu")
		(net "M_B_CPU1_SB_DQ<7>")
	)
	(segment
		(start 44.38142 -224.105724)
		(end 44.238926 -223.96323)
		(width 0.20066)
		(layer "F.Cu")
		(net "M_B_CPU1_SB_DQ<7>")
	)
	(segment
		(start 44.987464 -224.0915)
		(end 44.749466 -224.0915)
		(width 0.101854)
		(layer "F.Cu")
		(net "M_B_CPU1_SB_DQ<7>")
	)
	(segment
		(start 47.060358 -224.0915)
		(end 44.987464 -224.0915)
		(width 0.1016)
		(layer "F.Cu")
		(net "M_B_CPU1_SB_DQ<7>")
	)
	(segment
		(start 93.314266 -233.87812)
		(end 93.314012 -233.877866)
		(width 0.20066)
		(layer "F.Cu")
		(net "M_B_CPU1_SB_DQ<7>")
	)
	(segment
		(start 47.60468 -224.0915)
		(end 47.060358 -224.0915)
		(width 0.20066)
		(layer "F.Cu")
		(net "M_B_CPU1_SB_DQ<7>")
	)
	(segment
		(start 44.735242 -224.105724)
		(end 44.38142 -224.105724)
		(width 0.20066)
		(layer "F.Cu")
		(net "M_B_CPU1_SB_DQ<7>")
	)
	(segment
		(start 47.882302 -223.66224)
		(end 47.753778 -223.790764)
		(width 0.20066)
		(layer "F.Cu")
		(net "M_B_CPU1_SB_DQ<7>")
	)
	(segment
		(start 44.112942 -223.666558)
		(end 42.415714 -223.666558)
		(width 0.20066)
		(layer "F.Cu")
		(net "M_B_CPU1_SB_DQ<7>")
	)
	(segment
		(start 48.277526 -223.66224)
		(end 47.882302 -223.66224)
		(width 0.20066)
		(layer "F.Cu")
		(net "M_B_CPU1_SB_DQ<7>")
	)
	(segment
		(start 44.238926 -223.792542)
		(end 44.112942 -223.666558)
		(width 0.20066)
		(layer "F.Cu")
		(net "M_B_CPU1_SB_DQ<7>")
	)
	(segment
		(start 51.064414 -223.666558)
		(end 49.959514 -223.666558)
		(width 0.20066)
		(layer "F.Cu")
		(net "M_B_CPU1_SB_DQ<7>")
	)
	(segment
		(start 93.314012 -233.877866)
		(end 93.314012 -233.34218)
		(width 0.20066)
		(layer "F.Cu")
		(net "M_B_CPU1_SB_DQ<7>")
	)
	(segment
		(start 49.143412 -223.666558)
		(end 48.935894 -223.874076)
		(width 0.20066)
		(layer "F.Cu")
		(net "M_B_CPU1_SB_DQ<7>")
	)
	(segment
		(start 47.753778 -223.790764)
		(end 47.753778 -223.942402)
		(width 0.20066)
		(layer "F.Cu")
		(net "M_B_CPU1_SB_DQ<7>")
	)
	(segment
		(start 44.749466 -224.0915)
		(end 44.735242 -224.105724)
		(width 0.101854)
		(layer "F.Cu")
		(net "M_B_CPU1_SB_DQ<7>")
	)
	(segment
		(start 48.935894 -223.874076)
		(end 48.489362 -223.874076)
		(width 0.20066)
		(layer "F.Cu")
		(net "M_B_CPU1_SB_DQ<7>")
	)
	(segment
		(start 48.489362 -223.874076)
		(end 48.277526 -223.66224)
		(width 0.20066)
		(layer "F.Cu")
		(net "M_B_CPU1_SB_DQ<7>")
	)
	(segment
		(start 47.753778 -223.942402)
		(end 47.60468 -224.0915)
		(width 0.20066)
		(layer "F.Cu")
		(net "M_B_CPU1_SB_DQ<7>")
	)
	(segment
		(start 56.887364 -221.696788)
		(end 55.484014 -221.696788)
		(width 0.18288)
		(layer "In4.Cu")
		(net "M_B_CPU1_SB_DQ<7>")
	)
	(segment
		(start 64.741044 -220.642434)
		(end 62.925706 -220.642434)
		(width 0.18288)
		(layer "In4.Cu")
		(net "M_B_CPU1_SB_DQ<7>")
	)
	(segment
		(start 83.33359 -232.43159)
		(end 82.708496 -232.43159)
		(width 0.088646)
		(layer "In4.Cu")
		(net "M_B_CPU1_SB_DQ<7>")
	)
	(segment
		(start 53.593746 -222.025464)
		(end 53.410866 -221.842584)
		(width 0.18288)
		(layer "In4.Cu")
		(net "M_B_CPU1_SB_DQ<7>")
	)
	(segment
		(start 58.090562 -220.49359)
		(end 56.887364 -221.696788)
		(width 0.18288)
		(layer "In4.Cu")
		(net "M_B_CPU1_SB_DQ<7>")
	)
	(segment
		(start 65.050416 -220.951806)
		(end 64.741044 -220.642434)
		(width 0.18288)
		(layer "In4.Cu")
		(net "M_B_CPU1_SB_DQ<7>")
	)
	(segment
		(start 53.593746 -222.960946)
		(end 53.593746 -222.025464)
		(width 0.18288)
		(layer "In4.Cu")
		(net "M_B_CPU1_SB_DQ<7>")
	)
	(segment
		(start 54.978046 -223.143826)
		(end 53.776626 -223.143826)
		(width 0.18288)
		(layer "In4.Cu")
		(net "M_B_CPU1_SB_DQ<7>")
	)
	(segment
		(start 83.67903 -232.77703)
		(end 83.33359 -232.43159)
		(width 0.088646)
		(layer "In4.Cu")
		(net "M_B_CPU1_SB_DQ<7>")
	)
	(segment
		(start 52.719986 -223.143826)
		(end 51.587146 -223.143826)
		(width 0.18288)
		(layer "In4.Cu")
		(net "M_B_CPU1_SB_DQ<7>")
	)
	(segment
		(start 91.722956 -232.856024)
		(end 91.711272 -232.84942)
		(width 0.088646)
		(layer "In4.Cu")
		(net "M_B_CPU1_SB_DQ<7>")
	)
	(segment
		(start 88.903556 -232.856024)
		(end 88.893142 -232.850182)
		(width 0.088646)
		(layer "In4.Cu")
		(net "M_B_CPU1_SB_DQ<7>")
	)
	(segment
		(start 55.484014 -221.696788)
		(end 55.323994 -221.856808)
		(width 0.18288)
		(layer "In4.Cu")
		(net "M_B_CPU1_SB_DQ<7>")
	)
	(segment
		(start 52.902866 -222.960946)
		(end 52.719986 -223.143826)
		(width 0.18288)
		(layer "In4.Cu")
		(net "M_B_CPU1_SB_DQ<7>")
	)
	(segment
		(start 90.783156 -232.856024)
		(end 90.771472 -232.84942)
		(width 0.088646)
		(layer "In4.Cu")
		(net "M_B_CPU1_SB_DQ<7>")
	)
	(segment
		(start 82.708496 -232.43159)
		(end 76.181966 -232.43159)
		(width 0.18288)
		(layer "In4.Cu")
		(net "M_B_CPU1_SB_DQ<7>")
	)
	(segment
		(start 76.181966 -232.43159)
		(end 68.108068 -224.357692)
		(width 0.18288)
		(layer "In4.Cu")
		(net "M_B_CPU1_SB_DQ<7>")
	)
	(segment
		(start 52.902866 -222.025464)
		(end 52.902866 -222.960946)
		(width 0.18288)
		(layer "In4.Cu")
		(net "M_B_CPU1_SB_DQ<7>")
	)
	(segment
		(start 65.718436 -220.642434)
		(end 65.409064 -220.951806)
		(width 0.18288)
		(layer "In4.Cu")
		(net "M_B_CPU1_SB_DQ<7>")
	)
	(segment
		(start 62.75197 -220.81617)
		(end 59.416442 -220.81617)
		(width 0.18288)
		(layer "In4.Cu")
		(net "M_B_CPU1_SB_DQ<7>")
	)
	(segment
		(start 87.957914 -232.852722)
		(end 87.958168 -232.852722)
		(width 0.088646)
		(layer "In4.Cu")
		(net "M_B_CPU1_SB_DQ<7>")
	)
	(segment
		(start 55.323994 -222.797878)
		(end 54.978046 -223.143826)
		(width 0.18288)
		(layer "In4.Cu")
		(net "M_B_CPU1_SB_DQ<7>")
	)
	(segment
		(start 65.409064 -220.951806)
		(end 65.050416 -220.951806)
		(width 0.18288)
		(layer "In4.Cu")
		(net "M_B_CPU1_SB_DQ<7>")
	)
	(segment
		(start 51.587146 -223.143826)
		(end 51.064414 -223.666558)
		(width 0.18288)
		(layer "In4.Cu")
		(net "M_B_CPU1_SB_DQ<7>")
	)
	(segment
		(start 55.323994 -221.856808)
		(end 55.323994 -222.797878)
		(width 0.18288)
		(layer "In4.Cu")
		(net "M_B_CPU1_SB_DQ<7>")
	)
	(segment
		(start 86.078568 -232.852722)
		(end 86.068154 -232.846626)
		(width 0.088646)
		(layer "In4.Cu")
		(net "M_B_CPU1_SB_DQ<7>")
	)
	(segment
		(start 68.108068 -224.357692)
		(end 66.748406 -221.07525)
		(width 0.18288)
		(layer "In4.Cu")
		(net "M_B_CPU1_SB_DQ<7>")
	)
	(segment
		(start 53.410866 -221.842584)
		(end 53.085746 -221.842584)
		(width 0.18288)
		(layer "In4.Cu")
		(net "M_B_CPU1_SB_DQ<7>")
	)
	(segment
		(start 83.916266 -232.77703)
		(end 83.67903 -232.77703)
		(width 0.088646)
		(layer "In4.Cu")
		(net "M_B_CPU1_SB_DQ<7>")
	)
	(segment
		(start 53.776626 -223.143826)
		(end 53.593746 -222.960946)
		(width 0.18288)
		(layer "In4.Cu")
		(net "M_B_CPU1_SB_DQ<7>")
	)
	(segment
		(start 66.31559 -220.642434)
		(end 65.718436 -220.642434)
		(width 0.18288)
		(layer "In4.Cu")
		(net "M_B_CPU1_SB_DQ<7>")
	)
	(segment
		(start 89.843356 -232.856024)
		(end 89.831672 -232.84942)
		(width 0.088646)
		(layer "In4.Cu")
		(net "M_B_CPU1_SB_DQ<7>")
	)
	(segment
		(start 85.138514 -232.852722)
		(end 85.123782 -232.844086)
		(width 0.088646)
		(layer "In4.Cu")
		(net "M_B_CPU1_SB_DQ<7>")
	)
	(segment
		(start 59.416442 -220.81617)
		(end 59.093862 -220.49359)
		(width 0.18288)
		(layer "In4.Cu")
		(net "M_B_CPU1_SB_DQ<7>")
	)
	(segment
		(start 53.085746 -221.842584)
		(end 52.902866 -222.025464)
		(width 0.18288)
		(layer "In4.Cu")
		(net "M_B_CPU1_SB_DQ<7>")
	)
	(segment
		(start 66.748406 -221.07525)
		(end 66.31559 -220.642434)
		(width 0.18288)
		(layer "In4.Cu")
		(net "M_B_CPU1_SB_DQ<7>")
	)
	(segment
		(start 59.093862 -220.49359)
		(end 58.090562 -220.49359)
		(width 0.18288)
		(layer "In4.Cu")
		(net "M_B_CPU1_SB_DQ<7>")
	)
	(segment
		(start 62.925706 -220.642434)
		(end 62.75197 -220.81617)
		(width 0.18288)
		(layer "In4.Cu")
		(net "M_B_CPU1_SB_DQ<7>")
	)
	(segment
		(start 93.314012 -233.34218)
		(end 92.6846 -232.951528)
		(width 0.088646)
		(layer "In4.Cu")
		(net "M_B_CPU1_SB_DQ<7>")
	)
	(arc
		(start 86.068154 -232.846626)
		(mid 85.789722 -232.77678)
		(end 85.51291 -232.852722)
		(width 0.088646)
		(layer "In4.Cu")
		(net "M_B_CPU1_SB_DQ<7>")
	)
	(arc
		(start 85.51291 -232.852722)
		(mid 85.325712 -232.902865)
		(end 85.138514 -232.852722)
		(width 0.088646)
		(layer "In4.Cu")
		(net "M_B_CPU1_SB_DQ<7>")
	)
	(arc
		(start 92.091764 -232.852722)
		(mid 91.90781 -232.902851)
		(end 91.722956 -232.856024)
		(width 0.088646)
		(layer "In4.Cu")
		(net "M_B_CPU1_SB_DQ<7>")
	)
	(arc
		(start 87.018368 -232.852722)
		(mid 86.735666 -232.776946)
		(end 86.452964 -232.852722)
		(width 0.088646)
		(layer "In4.Cu")
		(net "M_B_CPU1_SB_DQ<7>")
	)
	(arc
		(start 84.198714 -232.852722)
		(mid 84.062472 -232.796288)
		(end 83.916266 -232.77703)
		(width 0.088646)
		(layer "In4.Cu")
		(net "M_B_CPU1_SB_DQ<7>")
	)
	(arc
		(start 91.711272 -232.84942)
		(mid 91.431167 -232.776978)
		(end 91.151964 -232.852722)
		(width 0.088646)
		(layer "In4.Cu")
		(net "M_B_CPU1_SB_DQ<7>")
	)
	(arc
		(start 89.831672 -232.84942)
		(mid 89.551567 -232.776978)
		(end 89.272364 -232.852722)
		(width 0.088646)
		(layer "In4.Cu")
		(net "M_B_CPU1_SB_DQ<7>")
	)
	(arc
		(start 89.272364 -232.852722)
		(mid 89.08841 -232.902851)
		(end 88.903556 -232.856024)
		(width 0.088646)
		(layer "In4.Cu")
		(net "M_B_CPU1_SB_DQ<7>")
	)
	(arc
		(start 90.771472 -232.84942)
		(mid 90.491367 -232.776978)
		(end 90.212164 -232.852722)
		(width 0.088646)
		(layer "In4.Cu")
		(net "M_B_CPU1_SB_DQ<7>")
	)
	(arc
		(start 92.612718 -232.89895)
		(mid 92.359549 -232.793506)
		(end 92.091764 -232.852722)
		(width 0.088646)
		(layer "In4.Cu")
		(net "M_B_CPU1_SB_DQ<7>")
	)
	(arc
		(start 86.452964 -232.852722)
		(mid 86.265766 -232.902865)
		(end 86.078568 -232.852722)
		(width 0.088646)
		(layer "In4.Cu")
		(net "M_B_CPU1_SB_DQ<7>")
	)
	(arc
		(start 88.893142 -232.850182)
		(mid 88.612507 -232.777014)
		(end 88.332564 -232.852722)
		(width 0.088646)
		(layer "In4.Cu")
		(net "M_B_CPU1_SB_DQ<7>")
	)
	(arc
		(start 90.212164 -232.852722)
		(mid 90.02821 -232.902851)
		(end 89.843356 -232.856024)
		(width 0.088646)
		(layer "In4.Cu")
		(net "M_B_CPU1_SB_DQ<7>")
	)
	(arc
		(start 84.57311 -232.852722)
		(mid 84.385912 -232.902865)
		(end 84.198714 -232.852722)
		(width 0.088646)
		(layer "In4.Cu")
		(net "M_B_CPU1_SB_DQ<7>")
	)
	(arc
		(start 87.392764 -232.852722)
		(mid 87.205566 -232.902865)
		(end 87.018368 -232.852722)
		(width 0.088646)
		(layer "In4.Cu")
		(net "M_B_CPU1_SB_DQ<7>")
	)
	(arc
		(start 88.332564 -232.852722)
		(mid 88.145256 -232.902865)
		(end 87.957914 -232.852722)
		(width 0.088646)
		(layer "In4.Cu")
		(net "M_B_CPU1_SB_DQ<7>")
	)
	(arc
		(start 85.123782 -232.844086)
		(mid 84.847307 -232.776766)
		(end 84.57311 -232.852722)
		(width 0.088646)
		(layer "In4.Cu")
		(net "M_B_CPU1_SB_DQ<7>")
	)
	(arc
		(start 91.151964 -232.852722)
		(mid 90.96801 -232.902851)
		(end 90.783156 -232.856024)
		(width 0.088646)
		(layer "In4.Cu")
		(net "M_B_CPU1_SB_DQ<7>")
	)
	(arc
		(start 92.6846 -232.951528)
		(mid 92.647697 -232.926554)
		(end 92.612718 -232.89895)
		(width 0.088646)
		(layer "In4.Cu")
		(net "M_B_CPU1_SB_DQ<7>")
	)
	(arc
		(start 87.958168 -232.852722)
		(mid 87.675466 -232.776946)
		(end 87.392764 -232.852722)
		(width 0.088646)
		(layer "In4.Cu")
		(net "M_B_CPU1_SB_DQ<7>")
	)
	(segment
		(start 44.735242 -224.931478)
		(end 43.99788 -224.931478)
		(width 0.20066)
		(layer "F.Cu")
		(net "M_B_CPU1_SB_DQ<6>")
	)
	(segment
		(start 47.83709 -225.085402)
		(end 47.693326 -224.941638)
		(width 0.20066)
		(layer "F.Cu")
		(net "M_B_CPU1_SB_DQ<6>")
	)
	(segment
		(start 45.000418 -224.941638)
		(end 44.745402 -224.941638)
		(width 0.101854)
		(layer "F.Cu")
		(net "M_B_CPU1_SB_DQ<6>")
	)
	(segment
		(start 47.060358 -224.941638)
		(end 45.000418 -224.941638)
		(width 0.1016)
		(layer "F.Cu")
		(net "M_B_CPU1_SB_DQ<6>")
	)
	(segment
		(start 48.64481 -225.36658)
		(end 48.432974 -225.578416)
		(width 0.20066)
		(layer "F.Cu")
		(net "M_B_CPU1_SB_DQ<6>")
	)
	(segment
		(start 48.004476 -225.578416)
		(end 47.83709 -225.41103)
		(width 0.20066)
		(layer "F.Cu")
		(net "M_B_CPU1_SB_DQ<6>")
	)
	(segment
		(start 47.693326 -224.941638)
		(end 47.060358 -224.941638)
		(width 0.20066)
		(layer "F.Cu")
		(net "M_B_CPU1_SB_DQ<6>")
	)
	(segment
		(start 49.959514 -225.36658)
		(end 48.64481 -225.36658)
		(width 0.20066)
		(layer "F.Cu")
		(net "M_B_CPU1_SB_DQ<6>")
	)
	(segment
		(start 43.99788 -224.931478)
		(end 43.562778 -225.36658)
		(width 0.20066)
		(layer "F.Cu")
		(net "M_B_CPU1_SB_DQ<6>")
	)
	(segment
		(start 44.745402 -224.941638)
		(end 44.735242 -224.931478)
		(width 0.101854)
		(layer "F.Cu")
		(net "M_B_CPU1_SB_DQ<6>")
	)
	(segment
		(start 43.562778 -225.36658)
		(end 42.415714 -225.36658)
		(width 0.20066)
		(layer "F.Cu")
		(net "M_B_CPU1_SB_DQ<6>")
	)
	(segment
		(start 93.784166 -234.691936)
		(end 93.784166 -234.15625)
		(width 0.20066)
		(layer "F.Cu")
		(net "M_B_CPU1_SB_DQ<6>")
	)
	(segment
		(start 48.432974 -225.578416)
		(end 48.004476 -225.578416)
		(width 0.20066)
		(layer "F.Cu")
		(net "M_B_CPU1_SB_DQ<6>")
	)
	(segment
		(start 51.064414 -225.36658)
		(end 49.959514 -225.36658)
		(width 0.20066)
		(layer "F.Cu")
		(net "M_B_CPU1_SB_DQ<6>")
	)
	(segment
		(start 47.83709 -225.41103)
		(end 47.83709 -225.085402)
		(width 0.20066)
		(layer "F.Cu")
		(net "M_B_CPU1_SB_DQ<6>")
	)
	(segment
		(start 93.783912 -234.69219)
		(end 93.784166 -234.691936)
		(width 0.20066)
		(layer "F.Cu")
		(net "M_B_CPU1_SB_DQ<6>")
	)
	(segment
		(start 90.682064 -233.666792)
		(end 90.677492 -233.669332)
		(width 0.088646)
		(layer "In4.Cu")
		(net "M_B_CPU1_SB_DQ<6>")
	)
	(segment
		(start 52.899564 -225.130106)
		(end 52.899564 -224.90303)
		(width 0.18288)
		(layer "In4.Cu")
		(net "M_B_CPU1_SB_DQ<6>")
	)
	(segment
		(start 83.157314 -233.42727)
		(end 82.708496 -233.42727)
		(width 0.088646)
		(layer "In4.Cu")
		(net "M_B_CPU1_SB_DQ<6>")
	)
	(segment
		(start 53.082444 -225.312986)
		(end 52.899564 -225.130106)
		(width 0.18288)
		(layer "In4.Cu")
		(net "M_B_CPU1_SB_DQ<6>")
	)
	(segment
		(start 57.257188 -223.866964)
		(end 56.088788 -223.866964)
		(width 0.18288)
		(layer "In4.Cu")
		(net "M_B_CPU1_SB_DQ<6>")
	)
	(segment
		(start 53.590444 -224.90303)
		(end 53.590444 -225.130106)
		(width 0.18288)
		(layer "In4.Cu")
		(net "M_B_CPU1_SB_DQ<6>")
	)
	(segment
		(start 88.80983 -233.662474)
		(end 88.802464 -233.666792)
		(width 0.088646)
		(layer "In4.Cu")
		(net "M_B_CPU1_SB_DQ<6>")
	)
	(segment
		(start 60.763912 -221.81312)
		(end 60.581032 -221.996)
		(width 0.18288)
		(layer "In4.Cu")
		(net "M_B_CPU1_SB_DQ<6>")
	)
	(segment
		(start 65.262252 -222.375476)
		(end 64.93256 -222.1992)
		(width 0.18288)
		(layer "In4.Cu")
		(net "M_B_CPU1_SB_DQ<6>")
	)
	(segment
		(start 93.784166 -234.15625)
		(end 93.240352 -233.738928)
		(width 0.088646)
		(layer "In4.Cu")
		(net "M_B_CPU1_SB_DQ<6>")
	)
	(segment
		(start 88.802464 -233.666792)
		(end 88.798654 -233.668824)
		(width 0.088646)
		(layer "In4.Cu")
		(net "M_B_CPU1_SB_DQ<6>")
	)
	(segment
		(start 63.60668 -222.305626)
		(end 63.355474 -222.556832)
		(width 0.18288)
		(layer "In4.Cu")
		(net "M_B_CPU1_SB_DQ<6>")
	)
	(segment
		(start 83.575652 -233.845608)
		(end 83.157314 -233.42727)
		(width 0.088646)
		(layer "In4.Cu")
		(net "M_B_CPU1_SB_DQ<6>")
	)
	(segment
		(start 91.621864 -233.666792)
		(end 91.617292 -233.669332)
		(width 0.088646)
		(layer "In4.Cu")
		(net "M_B_CPU1_SB_DQ<6>")
	)
	(segment
		(start 53.773324 -224.72015)
		(end 53.590444 -224.90303)
		(width 0.18288)
		(layer "In4.Cu")
		(net "M_B_CPU1_SB_DQ<6>")
	)
	(segment
		(start 83.98637 -233.756454)
		(end 83.897216 -233.845608)
		(width 0.088646)
		(layer "In4.Cu")
		(net "M_B_CPU1_SB_DQ<6>")
	)
	(segment
		(start 51.710844 -224.72015)
		(end 51.064414 -225.36658)
		(width 0.18288)
		(layer "In4.Cu")
		(net "M_B_CPU1_SB_DQ<6>")
	)
	(segment
		(start 64.93256 -222.1992)
		(end 64.716406 -222.264732)
		(width 0.18288)
		(layer "In4.Cu")
		(net "M_B_CPU1_SB_DQ<6>")
	)
	(segment
		(start 66.556128 -223.40951)
		(end 66.307208 -223.24314)
		(width 0.18288)
		(layer "In4.Cu")
		(net "M_B_CPU1_SB_DQ<6>")
	)
	(segment
		(start 75.664314 -233.42727)
		(end 67.200018 -224.962974)
		(width 0.18288)
		(layer "In4.Cu")
		(net "M_B_CPU1_SB_DQ<6>")
	)
	(segment
		(start 64.412876 -222.493332)
		(end 64.061594 -222.305626)
		(width 0.18288)
		(layer "In4.Cu")
		(net "M_B_CPU1_SB_DQ<6>")
	)
	(segment
		(start 64.061594 -222.305626)
		(end 63.60668 -222.305626)
		(width 0.18288)
		(layer "In4.Cu")
		(net "M_B_CPU1_SB_DQ<6>")
	)
	(segment
		(start 60.581032 -222.373952)
		(end 60.398152 -222.556832)
		(width 0.18288)
		(layer "In4.Cu")
		(net "M_B_CPU1_SB_DQ<6>")
	)
	(segment
		(start 65.306448 -222.971106)
		(end 65.240662 -222.754698)
		(width 0.18288)
		(layer "In4.Cu")
		(net "M_B_CPU1_SB_DQ<6>")
	)
	(segment
		(start 61.271912 -222.373952)
		(end 61.271912 -221.996)
		(width 0.18288)
		(layer "In4.Cu")
		(net "M_B_CPU1_SB_DQ<6>")
	)
	(segment
		(start 52.899564 -224.90303)
		(end 52.716684 -224.72015)
		(width 0.18288)
		(layer "In4.Cu")
		(net "M_B_CPU1_SB_DQ<6>")
	)
	(segment
		(start 59.490864 -222.556832)
		(end 58.75147 -223.296226)
		(width 0.18288)
		(layer "In4.Cu")
		(net "M_B_CPU1_SB_DQ<6>")
	)
	(segment
		(start 65.815464 -223.24314)
		(end 65.306448 -222.971106)
		(width 0.18288)
		(layer "In4.Cu")
		(net "M_B_CPU1_SB_DQ<6>")
	)
	(segment
		(start 90.68943 -233.662474)
		(end 90.682064 -233.666792)
		(width 0.088646)
		(layer "In4.Cu")
		(net "M_B_CPU1_SB_DQ<6>")
	)
	(segment
		(start 65.327784 -222.59163)
		(end 65.262252 -222.375476)
		(width 0.18288)
		(layer "In4.Cu")
		(net "M_B_CPU1_SB_DQ<6>")
	)
	(segment
		(start 58.75147 -223.296226)
		(end 57.827926 -223.296226)
		(width 0.18288)
		(layer "In4.Cu")
		(net "M_B_CPU1_SB_DQ<6>")
	)
	(segment
		(start 64.629284 -222.4278)
		(end 64.412876 -222.493332)
		(width 0.18288)
		(layer "In4.Cu")
		(net "M_B_CPU1_SB_DQ<6>")
	)
	(segment
		(start 91.62923 -233.662474)
		(end 91.621864 -233.666792)
		(width 0.088646)
		(layer "In4.Cu")
		(net "M_B_CPU1_SB_DQ<6>")
	)
	(segment
		(start 88.427814 -233.666538)
		(end 88.4174 -233.660442)
		(width 0.088646)
		(layer "In4.Cu")
		(net "M_B_CPU1_SB_DQ<6>")
	)
	(segment
		(start 65.240662 -222.754698)
		(end 65.327784 -222.59163)
		(width 0.18288)
		(layer "In4.Cu")
		(net "M_B_CPU1_SB_DQ<6>")
	)
	(segment
		(start 64.716406 -222.264732)
		(end 64.629284 -222.4278)
		(width 0.18288)
		(layer "In4.Cu")
		(net "M_B_CPU1_SB_DQ<6>")
	)
	(segment
		(start 83.897216 -233.845608)
		(end 83.575652 -233.845608)
		(width 0.088646)
		(layer "In4.Cu")
		(net "M_B_CPU1_SB_DQ<6>")
	)
	(segment
		(start 82.708496 -233.42727)
		(end 75.664314 -233.42727)
		(width 0.18288)
		(layer "In4.Cu")
		(net "M_B_CPU1_SB_DQ<6>")
	)
	(segment
		(start 53.407564 -225.312986)
		(end 53.082444 -225.312986)
		(width 0.18288)
		(layer "In4.Cu")
		(net "M_B_CPU1_SB_DQ<6>")
	)
	(segment
		(start 60.398152 -222.556832)
		(end 59.490864 -222.556832)
		(width 0.18288)
		(layer "In4.Cu")
		(net "M_B_CPU1_SB_DQ<6>")
	)
	(segment
		(start 61.454792 -222.556832)
		(end 61.271912 -222.373952)
		(width 0.18288)
		(layer "In4.Cu")
		(net "M_B_CPU1_SB_DQ<6>")
	)
	(segment
		(start 61.089032 -221.81312)
		(end 60.763912 -221.81312)
		(width 0.18288)
		(layer "In4.Cu")
		(net "M_B_CPU1_SB_DQ<6>")
	)
	(segment
		(start 66.307208 -223.24314)
		(end 65.815464 -223.24314)
		(width 0.18288)
		(layer "In4.Cu")
		(net "M_B_CPU1_SB_DQ<6>")
	)
	(segment
		(start 52.716684 -224.72015)
		(end 51.710844 -224.72015)
		(width 0.18288)
		(layer "In4.Cu")
		(net "M_B_CPU1_SB_DQ<6>")
	)
	(segment
		(start 61.271912 -221.996)
		(end 61.089032 -221.81312)
		(width 0.18288)
		(layer "In4.Cu")
		(net "M_B_CPU1_SB_DQ<6>")
	)
	(segment
		(start 60.581032 -221.996)
		(end 60.581032 -222.373952)
		(width 0.18288)
		(layer "In4.Cu")
		(net "M_B_CPU1_SB_DQ<6>")
	)
	(segment
		(start 57.827926 -223.296226)
		(end 57.257188 -223.866964)
		(width 0.18288)
		(layer "In4.Cu")
		(net "M_B_CPU1_SB_DQ<6>")
	)
	(segment
		(start 63.355474 -222.556832)
		(end 61.454792 -222.556832)
		(width 0.18288)
		(layer "In4.Cu")
		(net "M_B_CPU1_SB_DQ<6>")
	)
	(segment
		(start 55.235602 -224.72015)
		(end 53.773324 -224.72015)
		(width 0.18288)
		(layer "In4.Cu")
		(net "M_B_CPU1_SB_DQ<6>")
	)
	(segment
		(start 56.088788 -223.866964)
		(end 55.235602 -224.72015)
		(width 0.18288)
		(layer "In4.Cu")
		(net "M_B_CPU1_SB_DQ<6>")
	)
	(segment
		(start 88.427814 -233.666792)
		(end 88.427814 -233.666538)
		(width 0.088646)
		(layer "In4.Cu")
		(net "M_B_CPU1_SB_DQ<6>")
	)
	(segment
		(start 89.74963 -233.662474)
		(end 89.737692 -233.669332)
		(width 0.088646)
		(layer "In4.Cu")
		(net "M_B_CPU1_SB_DQ<6>")
	)
	(segment
		(start 53.590444 -225.130106)
		(end 53.407564 -225.312986)
		(width 0.18288)
		(layer "In4.Cu")
		(net "M_B_CPU1_SB_DQ<6>")
	)
	(segment
		(start 67.200018 -224.962974)
		(end 66.556128 -223.40951)
		(width 0.18288)
		(layer "In4.Cu")
		(net "M_B_CPU1_SB_DQ<6>")
	)
	(arc
		(start 91.617292 -233.669332)
		(mid 91.431907 -233.71697)
		(end 91.247214 -233.666792)
		(width 0.088646)
		(layer "In4.Cu")
		(net "M_B_CPU1_SB_DQ<6>")
	)
	(arc
		(start 90.677492 -233.669332)
		(mid 90.492107 -233.71697)
		(end 90.307414 -233.666792)
		(width 0.088646)
		(layer "In4.Cu")
		(net "M_B_CPU1_SB_DQ<6>")
	)
	(arc
		(start 85.608668 -233.666538)
		(mid 85.325966 -233.590796)
		(end 85.043264 -233.666538)
		(width 0.088646)
		(layer "In4.Cu")
		(net "M_B_CPU1_SB_DQ<6>")
	)
	(arc
		(start 93.240352 -233.738928)
		(mid 92.901865 -233.606688)
		(end 92.545154 -233.675936)
		(width 0.088646)
		(layer "In4.Cu")
		(net "M_B_CPU1_SB_DQ<6>")
	)
	(arc
		(start 88.798654 -233.668824)
		(mid 88.612964 -233.716902)
		(end 88.427814 -233.666792)
		(width 0.088646)
		(layer "In4.Cu")
		(net "M_B_CPU1_SB_DQ<6>")
	)
	(arc
		(start 84.668868 -233.666538)
		(mid 84.312345 -233.595635)
		(end 83.98637 -233.756454)
		(width 0.088646)
		(layer "In4.Cu")
		(net "M_B_CPU1_SB_DQ<6>")
	)
	(arc
		(start 91.247214 -233.666792)
		(mid 90.968891 -233.591033)
		(end 90.68943 -233.662474)
		(width 0.088646)
		(layer "In4.Cu")
		(net "M_B_CPU1_SB_DQ<6>")
	)
	(arc
		(start 90.307414 -233.666792)
		(mid 90.029091 -233.591033)
		(end 89.74963 -233.662474)
		(width 0.088646)
		(layer "In4.Cu")
		(net "M_B_CPU1_SB_DQ<6>")
	)
	(arc
		(start 85.043264 -233.666538)
		(mid 84.856066 -233.716681)
		(end 84.668868 -233.666538)
		(width 0.088646)
		(layer "In4.Cu")
		(net "M_B_CPU1_SB_DQ<6>")
	)
	(arc
		(start 85.983064 -233.666538)
		(mid 85.795866 -233.716681)
		(end 85.608668 -233.666538)
		(width 0.088646)
		(layer "In4.Cu")
		(net "M_B_CPU1_SB_DQ<6>")
	)
	(arc
		(start 92.545154 -233.675936)
		(mid 92.364918 -233.716928)
		(end 92.187014 -233.666792)
		(width 0.088646)
		(layer "In4.Cu")
		(net "M_B_CPU1_SB_DQ<6>")
	)
	(arc
		(start 88.4174 -233.660442)
		(mid 88.139222 -233.59075)
		(end 87.862664 -233.666538)
		(width 0.088646)
		(layer "In4.Cu")
		(net "M_B_CPU1_SB_DQ<6>")
	)
	(arc
		(start 86.922864 -233.666538)
		(mid 86.735666 -233.716681)
		(end 86.548468 -233.666538)
		(width 0.088646)
		(layer "In4.Cu")
		(net "M_B_CPU1_SB_DQ<6>")
	)
	(arc
		(start 87.488268 -233.666538)
		(mid 87.205566 -233.590796)
		(end 86.922864 -233.666538)
		(width 0.088646)
		(layer "In4.Cu")
		(net "M_B_CPU1_SB_DQ<6>")
	)
	(arc
		(start 89.737692 -233.669332)
		(mid 89.552307 -233.71697)
		(end 89.367614 -233.666792)
		(width 0.088646)
		(layer "In4.Cu")
		(net "M_B_CPU1_SB_DQ<6>")
	)
	(arc
		(start 86.548468 -233.666538)
		(mid 86.265766 -233.590796)
		(end 85.983064 -233.666538)
		(width 0.088646)
		(layer "In4.Cu")
		(net "M_B_CPU1_SB_DQ<6>")
	)
	(arc
		(start 87.862664 -233.666538)
		(mid 87.675466 -233.716681)
		(end 87.488268 -233.666538)
		(width 0.088646)
		(layer "In4.Cu")
		(net "M_B_CPU1_SB_DQ<6>")
	)
	(arc
		(start 92.187014 -233.666792)
		(mid 91.908691 -233.591033)
		(end 91.62923 -233.662474)
		(width 0.088646)
		(layer "In4.Cu")
		(net "M_B_CPU1_SB_DQ<6>")
	)
	(arc
		(start 89.367614 -233.666792)
		(mid 89.089291 -233.591033)
		(end 88.80983 -233.662474)
		(width 0.088646)
		(layer "In4.Cu")
		(net "M_B_CPU1_SB_DQ<6>")
	)
	(segment
		(start 39.861236 -224.728024)
		(end 39.649908 -224.516696)
		(width 0.20066)
		(layer "F.Cu")
		(net "M_B_CPU1_SB_DQ<5>")
	)
	(segment
		(start 92.374212 -233.877866)
		(end 92.374212 -233.34218)
		(width 0.20066)
		(layer "F.Cu")
		(net "M_B_CPU1_SB_DQ<5>")
	)
	(segment
		(start 46.964346 -224.516696)
		(end 45.859446 -224.516696)
		(width 0.20066)
		(layer "F.Cu")
		(net "M_B_CPU1_SB_DQ<5>")
	)
	(segment
		(start 43.795188 -224.091754)
		(end 43.616626 -224.091754)
		(width 0.20066)
		(layer "F.Cu")
		(net "M_B_CPU1_SB_DQ<5>")
	)
	(segment
		(start 41.29151 -224.082864)
		(end 40.682672 -224.082864)
		(width 0.20066)
		(layer "F.Cu")
		(net "M_B_CPU1_SB_DQ<5>")
	)
	(segment
		(start 41.3004 -224.091754)
		(end 41.29151 -224.082864)
		(width 0.1016)
		(layer "F.Cu")
		(net "M_B_CPU1_SB_DQ<5>")
	)
	(segment
		(start 40.520112 -224.245424)
		(end 40.520112 -224.573592)
		(width 0.20066)
		(layer "F.Cu")
		(net "M_B_CPU1_SB_DQ<5>")
	)
	(segment
		(start 92.374466 -233.87812)
		(end 92.374212 -233.877866)
		(width 0.20066)
		(layer "F.Cu")
		(net "M_B_CPU1_SB_DQ<5>")
	)
	(segment
		(start 44.22013 -224.516696)
		(end 43.795188 -224.091754)
		(width 0.20066)
		(layer "F.Cu")
		(net "M_B_CPU1_SB_DQ<5>")
	)
	(segment
		(start 40.520112 -224.573592)
		(end 40.36568 -224.728024)
		(width 0.20066)
		(layer "F.Cu")
		(net "M_B_CPU1_SB_DQ<5>")
	)
	(segment
		(start 43.616626 -224.091754)
		(end 43.285918 -224.091754)
		(width 0.101854)
		(layer "F.Cu")
		(net "M_B_CPU1_SB_DQ<5>")
	)
	(segment
		(start 45.859446 -224.516696)
		(end 44.22013 -224.516696)
		(width 0.20066)
		(layer "F.Cu")
		(net "M_B_CPU1_SB_DQ<5>")
	)
	(segment
		(start 40.682672 -224.082864)
		(end 40.520112 -224.245424)
		(width 0.20066)
		(layer "F.Cu")
		(net "M_B_CPU1_SB_DQ<5>")
	)
	(segment
		(start 40.36568 -224.728024)
		(end 39.861236 -224.728024)
		(width 0.20066)
		(layer "F.Cu")
		(net "M_B_CPU1_SB_DQ<5>")
	)
	(segment
		(start 43.285918 -224.091754)
		(end 41.3004 -224.091754)
		(width 0.1016)
		(layer "F.Cu")
		(net "M_B_CPU1_SB_DQ<5>")
	)
	(segment
		(start 39.649908 -224.516696)
		(end 38.315646 -224.516696)
		(width 0.20066)
		(layer "F.Cu")
		(net "M_B_CPU1_SB_DQ<5>")
	)
	(segment
		(start 55.036466 -224.091754)
		(end 47.389288 -224.091754)
		(width 0.18288)
		(layer "In4.Cu")
		(net "M_B_CPU1_SB_DQ<5>")
	)
	(segment
		(start 82.708496 -232.92943)
		(end 75.93965 -232.92943)
		(width 0.18288)
		(layer "In4.Cu")
		(net "M_B_CPU1_SB_DQ<5>")
	)
	(segment
		(start 62.641226 -221.585282)
		(end 62.371224 -221.31528)
		(width 0.18288)
		(layer "In4.Cu")
		(net "M_B_CPU1_SB_DQ<5>")
	)
	(segment
		(start 57.89549 -222.200216)
		(end 56.775604 -223.320102)
		(width 0.18288)
		(layer "In4.Cu")
		(net "M_B_CPU1_SB_DQ<5>")
	)
	(segment
		(start 89.748106 -233.021124)
		(end 89.736422 -233.01452)
		(width 0.088646)
		(layer "In4.Cu")
		(net "M_B_CPU1_SB_DQ<5>")
	)
	(segment
		(start 85.057996 -233.026458)
		(end 85.043264 -233.017822)
		(width 0.088646)
		(layer "In4.Cu")
		(net "M_B_CPU1_SB_DQ<5>")
	)
	(segment
		(start 90.687906 -233.021124)
		(end 90.676222 -233.01452)
		(width 0.088646)
		(layer "In4.Cu")
		(net "M_B_CPU1_SB_DQ<5>")
	)
	(segment
		(start 59.391042 -221.31528)
		(end 58.506106 -222.200216)
		(width 0.18288)
		(layer "In4.Cu")
		(net "M_B_CPU1_SB_DQ<5>")
	)
	(segment
		(start 84.118196 -233.026458)
		(end 84.103464 -233.017822)
		(width 0.088646)
		(layer "In4.Cu")
		(net "M_B_CPU1_SB_DQ<5>")
	)
	(segment
		(start 83.104482 -232.92943)
		(end 82.708496 -232.92943)
		(width 0.088646)
		(layer "In4.Cu")
		(net "M_B_CPU1_SB_DQ<5>")
	)
	(segment
		(start 67.68338 -224.67316)
		(end 66.729864 -222.371158)
		(width 0.18288)
		(layer "In4.Cu")
		(net "M_B_CPU1_SB_DQ<5>")
	)
	(segment
		(start 83.916266 -232.967276)
		(end 83.76158 -232.967276)
		(width 0.088646)
		(layer "In4.Cu")
		(net "M_B_CPU1_SB_DQ<5>")
	)
	(segment
		(start 62.371224 -221.31528)
		(end 59.391042 -221.31528)
		(width 0.18288)
		(layer "In4.Cu")
		(net "M_B_CPU1_SB_DQ<5>")
	)
	(segment
		(start 83.64093 -233.087926)
		(end 83.262978 -233.087926)
		(width 0.088646)
		(layer "In4.Cu")
		(net "M_B_CPU1_SB_DQ<5>")
	)
	(segment
		(start 47.389288 -224.091754)
		(end 46.964346 -224.516696)
		(width 0.18288)
		(layer "In4.Cu")
		(net "M_B_CPU1_SB_DQ<5>")
	)
	(segment
		(start 91.627706 -233.021124)
		(end 91.616022 -233.01452)
		(width 0.088646)
		(layer "In4.Cu")
		(net "M_B_CPU1_SB_DQ<5>")
	)
	(segment
		(start 88.808306 -233.021124)
		(end 88.802464 -233.017822)
		(width 0.088646)
		(layer "In4.Cu")
		(net "M_B_CPU1_SB_DQ<5>")
	)
	(segment
		(start 55.808118 -223.320102)
		(end 55.036466 -224.091754)
		(width 0.18288)
		(layer "In4.Cu")
		(net "M_B_CPU1_SB_DQ<5>")
	)
	(segment
		(start 75.93965 -232.92943)
		(end 67.68338 -224.67316)
		(width 0.18288)
		(layer "In4.Cu")
		(net "M_B_CPU1_SB_DQ<5>")
	)
	(segment
		(start 88.802464 -233.017822)
		(end 88.798654 -233.015536)
		(width 0.088646)
		(layer "In4.Cu")
		(net "M_B_CPU1_SB_DQ<5>")
	)
	(segment
		(start 83.76158 -232.967276)
		(end 83.64093 -233.087926)
		(width 0.088646)
		(layer "In4.Cu")
		(net "M_B_CPU1_SB_DQ<5>")
	)
	(segment
		(start 66.729864 -222.371158)
		(end 65.943988 -221.585282)
		(width 0.18288)
		(layer "In4.Cu")
		(net "M_B_CPU1_SB_DQ<5>")
	)
	(segment
		(start 56.775604 -223.320102)
		(end 55.808118 -223.320102)
		(width 0.18288)
		(layer "In4.Cu")
		(net "M_B_CPU1_SB_DQ<5>")
	)
	(segment
		(start 58.506106 -222.200216)
		(end 57.89549 -222.200216)
		(width 0.18288)
		(layer "In4.Cu")
		(net "M_B_CPU1_SB_DQ<5>")
	)
	(segment
		(start 83.262978 -233.087926)
		(end 83.104482 -232.92943)
		(width 0.088646)
		(layer "In4.Cu")
		(net "M_B_CPU1_SB_DQ<5>")
	)
	(segment
		(start 65.943988 -221.585282)
		(end 62.641226 -221.585282)
		(width 0.18288)
		(layer "In4.Cu")
		(net "M_B_CPU1_SB_DQ<5>")
	)
	(arc
		(start 89.367614 -233.017822)
		(mid 89.088411 -233.093462)
		(end 88.808306 -233.021124)
		(width 0.088646)
		(layer "In4.Cu")
		(net "M_B_CPU1_SB_DQ<5>")
	)
	(arc
		(start 91.616022 -233.01452)
		(mid 91.431167 -232.96757)
		(end 91.247214 -233.017822)
		(width 0.088646)
		(layer "In4.Cu")
		(net "M_B_CPU1_SB_DQ<5>")
	)
	(arc
		(start 88.798654 -233.015536)
		(mid 88.612935 -232.967584)
		(end 88.427814 -233.017822)
		(width 0.088646)
		(layer "In4.Cu")
		(net "M_B_CPU1_SB_DQ<5>")
	)
	(arc
		(start 84.103464 -233.017822)
		(mid 84.013192 -232.980223)
		(end 83.916266 -232.967276)
		(width 0.088646)
		(layer "In4.Cu")
		(net "M_B_CPU1_SB_DQ<5>")
	)
	(arc
		(start 90.307414 -233.017822)
		(mid 90.028211 -233.093462)
		(end 89.748106 -233.021124)
		(width 0.088646)
		(layer "In4.Cu")
		(net "M_B_CPU1_SB_DQ<5>")
	)
	(arc
		(start 88.427814 -233.017822)
		(mid 88.145256 -233.093471)
		(end 87.862664 -233.017822)
		(width 0.088646)
		(layer "In4.Cu")
		(net "M_B_CPU1_SB_DQ<5>")
	)
	(arc
		(start 87.488268 -233.017822)
		(mid 87.205566 -233.093598)
		(end 86.922864 -233.017822)
		(width 0.088646)
		(layer "In4.Cu")
		(net "M_B_CPU1_SB_DQ<5>")
	)
	(arc
		(start 86.922864 -233.017822)
		(mid 86.735666 -232.967679)
		(end 86.548468 -233.017822)
		(width 0.088646)
		(layer "In4.Cu")
		(net "M_B_CPU1_SB_DQ<5>")
	)
	(arc
		(start 86.548468 -233.017822)
		(mid 86.265766 -233.093598)
		(end 85.983064 -233.017822)
		(width 0.088646)
		(layer "In4.Cu")
		(net "M_B_CPU1_SB_DQ<5>")
	)
	(arc
		(start 85.983064 -233.017822)
		(mid 85.795866 -232.967679)
		(end 85.608668 -233.017822)
		(width 0.088646)
		(layer "In4.Cu")
		(net "M_B_CPU1_SB_DQ<5>")
	)
	(arc
		(start 84.668868 -233.017822)
		(mid 84.394669 -233.093657)
		(end 84.118196 -233.026458)
		(width 0.088646)
		(layer "In4.Cu")
		(net "M_B_CPU1_SB_DQ<5>")
	)
	(arc
		(start 91.247214 -233.017822)
		(mid 90.968011 -233.093462)
		(end 90.687906 -233.021124)
		(width 0.088646)
		(layer "In4.Cu")
		(net "M_B_CPU1_SB_DQ<5>")
	)
	(arc
		(start 92.187014 -233.017822)
		(mid 91.907811 -233.093462)
		(end 91.627706 -233.021124)
		(width 0.088646)
		(layer "In4.Cu")
		(net "M_B_CPU1_SB_DQ<5>")
	)
	(arc
		(start 85.608668 -233.017822)
		(mid 85.334469 -233.093657)
		(end 85.057996 -233.026458)
		(width 0.088646)
		(layer "In4.Cu")
		(net "M_B_CPU1_SB_DQ<5>")
	)
	(arc
		(start 89.736422 -233.01452)
		(mid 89.551567 -232.96757)
		(end 89.367614 -233.017822)
		(width 0.088646)
		(layer "In4.Cu")
		(net "M_B_CPU1_SB_DQ<5>")
	)
	(arc
		(start 85.043264 -233.017822)
		(mid 84.856066 -232.967679)
		(end 84.668868 -233.017822)
		(width 0.088646)
		(layer "In4.Cu")
		(net "M_B_CPU1_SB_DQ<5>")
	)
	(arc
		(start 90.676222 -233.01452)
		(mid 90.491367 -232.96757)
		(end 90.307414 -233.017822)
		(width 0.088646)
		(layer "In4.Cu")
		(net "M_B_CPU1_SB_DQ<5>")
	)
	(arc
		(start 92.374212 -233.34218)
		(mid 92.442625 -233.086552)
		(end 92.187014 -233.017822)
		(width 0.088646)
		(layer "In4.Cu")
		(net "M_B_CPU1_SB_DQ<5>")
	)
	(arc
		(start 87.862664 -233.017822)
		(mid 87.675466 -232.967679)
		(end 87.488268 -233.017822)
		(width 0.088646)
		(layer "In4.Cu")
		(net "M_B_CPU1_SB_DQ<5>")
	)
	(segment
		(start 91.904312 -234.69219)
		(end 91.904566 -234.691936)
		(width 0.20066)
		(layer "F.Cu")
		(net "M_B_CPU1_SB_DQ<4>")
	)
	(segment
		(start 40.520112 -226.282758)
		(end 40.347392 -226.455478)
		(width 0.20066)
		(layer "F.Cu")
		(net "M_B_CPU1_SB_DQ<4>")
	)
	(segment
		(start 43.616626 -225.791776)
		(end 41.547542 -225.791776)
		(width 0.1016)
		(layer "F.Cu")
		(net "M_B_CPU1_SB_DQ<4>")
	)
	(segment
		(start 44.065444 -225.791776)
		(end 43.616626 -225.791776)
		(width 0.20066)
		(layer "F.Cu")
		(net "M_B_CPU1_SB_DQ<4>")
	)
	(segment
		(start 45.859446 -226.216718)
		(end 44.490386 -226.216718)
		(width 0.20066)
		(layer "F.Cu")
		(net "M_B_CPU1_SB_DQ<4>")
	)
	(segment
		(start 40.520112 -225.993198)
		(end 40.520112 -226.282758)
		(width 0.20066)
		(layer "F.Cu")
		(net "M_B_CPU1_SB_DQ<4>")
	)
	(segment
		(start 39.888668 -226.455478)
		(end 39.649908 -226.216718)
		(width 0.20066)
		(layer "F.Cu")
		(net "M_B_CPU1_SB_DQ<4>")
	)
	(segment
		(start 40.347392 -226.455478)
		(end 39.888668 -226.455478)
		(width 0.20066)
		(layer "F.Cu")
		(net "M_B_CPU1_SB_DQ<4>")
	)
	(segment
		(start 41.299638 -225.791776)
		(end 41.29151 -225.783648)
		(width 0.101854)
		(layer "F.Cu")
		(net "M_B_CPU1_SB_DQ<4>")
	)
	(segment
		(start 40.729662 -225.783648)
		(end 40.520112 -225.993198)
		(width 0.20066)
		(layer "F.Cu")
		(net "M_B_CPU1_SB_DQ<4>")
	)
	(segment
		(start 91.904566 -234.691936)
		(end 91.904566 -234.15625)
		(width 0.20066)
		(layer "F.Cu")
		(net "M_B_CPU1_SB_DQ<4>")
	)
	(segment
		(start 41.29151 -225.783648)
		(end 40.729662 -225.783648)
		(width 0.20066)
		(layer "F.Cu")
		(net "M_B_CPU1_SB_DQ<4>")
	)
	(segment
		(start 41.547542 -225.791776)
		(end 41.299638 -225.791776)
		(width 0.101854)
		(layer "F.Cu")
		(net "M_B_CPU1_SB_DQ<4>")
	)
	(segment
		(start 44.490386 -226.216718)
		(end 44.065444 -225.791776)
		(width 0.20066)
		(layer "F.Cu")
		(net "M_B_CPU1_SB_DQ<4>")
	)
	(segment
		(start 39.649908 -226.216718)
		(end 38.315646 -226.216718)
		(width 0.20066)
		(layer "F.Cu")
		(net "M_B_CPU1_SB_DQ<4>")
	)
	(segment
		(start 46.964346 -226.216718)
		(end 45.859446 -226.216718)
		(width 0.20066)
		(layer "F.Cu")
		(net "M_B_CPU1_SB_DQ<4>")
	)
	(segment
		(start 64.499998 -223.77781)
		(end 64.310768 -223.96704)
		(width 0.18288)
		(layer "In4.Cu")
		(net "M_B_CPU1_SB_DQ<4>")
	)
	(segment
		(start 83.36407 -233.92511)
		(end 82.708496 -233.92511)
		(width 0.088646)
		(layer "In4.Cu")
		(net "M_B_CPU1_SB_DQ<4>")
	)
	(segment
		(start 88.332564 -233.831638)
		(end 88.332564 -233.831892)
		(width 0.088646)
		(layer "In4.Cu")
		(net "M_B_CPU1_SB_DQ<4>")
	)
	(segment
		(start 64.990472 -224.268284)
		(end 64.990472 -224.042224)
		(width 0.18288)
		(layer "In4.Cu")
		(net "M_B_CPU1_SB_DQ<4>")
	)
	(segment
		(start 64.93383 -224.550986)
		(end 64.93383 -224.324926)
		(width 0.18288)
		(layer "In4.Cu")
		(net "M_B_CPU1_SB_DQ<4>")
	)
	(segment
		(start 51.584098 -225.810826)
		(end 51.565048 -225.791776)
		(width 0.18288)
		(layer "In4.Cu")
		(net "M_B_CPU1_SB_DQ<4>")
	)
	(segment
		(start 75.405234 -233.92511)
		(end 66.423794 -224.94367)
		(width 0.18288)
		(layer "In4.Cu")
		(net "M_B_CPU1_SB_DQ<4>")
	)
	(segment
		(start 48.37049 -225.252788)
		(end 48.37049 -225.608896)
		(width 0.18288)
		(layer "In4.Cu")
		(net "M_B_CPU1_SB_DQ<4>")
	)
	(segment
		(start 64.310768 -223.96704)
		(end 64.035686 -223.96704)
		(width 0.18288)
		(layer "In4.Cu")
		(net "M_B_CPU1_SB_DQ<4>")
	)
	(segment
		(start 64.990472 -224.042224)
		(end 64.726058 -223.77781)
		(width 0.18288)
		(layer "In4.Cu")
		(net "M_B_CPU1_SB_DQ<4>")
	)
	(segment
		(start 56.227726 -225.810826)
		(end 51.584098 -225.810826)
		(width 0.18288)
		(layer "In4.Cu")
		(net "M_B_CPU1_SB_DQ<4>")
	)
	(segment
		(start 48.87849 -225.069908)
		(end 48.55337 -225.069908)
		(width 0.18288)
		(layer "In4.Cu")
		(net "M_B_CPU1_SB_DQ<4>")
	)
	(segment
		(start 83.97621 -234.035854)
		(end 83.474814 -234.035854)
		(width 0.088646)
		(layer "In4.Cu")
		(net "M_B_CPU1_SB_DQ<4>")
	)
	(segment
		(start 91.904566 -234.15625)
		(end 91.454732 -233.997246)
		(width 0.088646)
		(layer "In4.Cu")
		(net "M_B_CPU1_SB_DQ<4>")
	)
	(segment
		(start 51.565048 -225.791776)
		(end 49.24425 -225.791776)
		(width 0.18288)
		(layer "In4.Cu")
		(net "M_B_CPU1_SB_DQ<4>")
	)
	(segment
		(start 82.708496 -233.92511)
		(end 75.405234 -233.92511)
		(width 0.18288)
		(layer "In4.Cu")
		(net "M_B_CPU1_SB_DQ<4>")
	)
	(segment
		(start 49.24425 -225.791776)
		(end 49.06137 -225.608896)
		(width 0.18288)
		(layer "In4.Cu")
		(net "M_B_CPU1_SB_DQ<4>")
	)
	(segment
		(start 48.37049 -225.608896)
		(end 48.18761 -225.791776)
		(width 0.18288)
		(layer "In4.Cu")
		(net "M_B_CPU1_SB_DQ<4>")
	)
	(segment
		(start 90.777314 -233.831638)
		(end 90.769948 -233.835956)
		(width 0.088646)
		(layer "In4.Cu")
		(net "M_B_CPU1_SB_DQ<4>")
	)
	(segment
		(start 47.389288 -225.791776)
		(end 46.964346 -226.216718)
		(width 0.18288)
		(layer "In4.Cu")
		(net "M_B_CPU1_SB_DQ<4>")
	)
	(segment
		(start 48.18761 -225.791776)
		(end 47.389288 -225.791776)
		(width 0.18288)
		(layer "In4.Cu")
		(net "M_B_CPU1_SB_DQ<4>")
	)
	(segment
		(start 48.55337 -225.069908)
		(end 48.37049 -225.252788)
		(width 0.18288)
		(layer "In4.Cu")
		(net "M_B_CPU1_SB_DQ<4>")
	)
	(segment
		(start 90.781886 -233.829098)
		(end 90.777314 -233.831638)
		(width 0.088646)
		(layer "In4.Cu")
		(net "M_B_CPU1_SB_DQ<4>")
	)
	(segment
		(start 59.661298 -223.129348)
		(end 58.88609 -223.904556)
		(width 0.18288)
		(layer "In4.Cu")
		(net "M_B_CPU1_SB_DQ<4>")
	)
	(segment
		(start 64.93383 -224.324926)
		(end 64.990472 -224.268284)
		(width 0.18288)
		(layer "In4.Cu")
		(net "M_B_CPU1_SB_DQ<4>")
	)
	(segment
		(start 58.133996 -223.904556)
		(end 56.227726 -225.810826)
		(width 0.18288)
		(layer "In4.Cu")
		(net "M_B_CPU1_SB_DQ<4>")
	)
	(segment
		(start 65.326514 -224.94367)
		(end 64.93383 -224.550986)
		(width 0.18288)
		(layer "In4.Cu")
		(net "M_B_CPU1_SB_DQ<4>")
	)
	(segment
		(start 91.374214 -233.960162)
		(end 91.151964 -233.831638)
		(width 0.088646)
		(layer "In4.Cu")
		(net "M_B_CPU1_SB_DQ<4>")
	)
	(segment
		(start 49.06137 -225.608896)
		(end 49.06137 -225.252788)
		(width 0.18288)
		(layer "In4.Cu")
		(net "M_B_CPU1_SB_DQ<4>")
	)
	(segment
		(start 49.06137 -225.252788)
		(end 48.87849 -225.069908)
		(width 0.18288)
		(layer "In4.Cu")
		(net "M_B_CPU1_SB_DQ<4>")
	)
	(segment
		(start 63.197994 -223.129348)
		(end 59.661298 -223.129348)
		(width 0.18288)
		(layer "In4.Cu")
		(net "M_B_CPU1_SB_DQ<4>")
	)
	(segment
		(start 83.474814 -234.035854)
		(end 83.36407 -233.92511)
		(width 0.088646)
		(layer "In4.Cu")
		(net "M_B_CPU1_SB_DQ<4>")
	)
	(segment
		(start 64.035686 -223.96704)
		(end 63.197994 -223.129348)
		(width 0.18288)
		(layer "In4.Cu")
		(net "M_B_CPU1_SB_DQ<4>")
	)
	(segment
		(start 84.12099 -233.891074)
		(end 83.97621 -234.035854)
		(width 0.088646)
		(layer "In4.Cu")
		(net "M_B_CPU1_SB_DQ<4>")
	)
	(segment
		(start 64.726058 -223.77781)
		(end 64.499998 -223.77781)
		(width 0.18288)
		(layer "In4.Cu")
		(net "M_B_CPU1_SB_DQ<4>")
	)
	(segment
		(start 88.897714 -233.831638)
		(end 88.893142 -233.834432)
		(width 0.088646)
		(layer "In4.Cu")
		(net "M_B_CPU1_SB_DQ<4>")
	)
	(segment
		(start 66.423794 -224.94367)
		(end 65.326514 -224.94367)
		(width 0.18288)
		(layer "In4.Cu")
		(net "M_B_CPU1_SB_DQ<4>")
	)
	(segment
		(start 58.88609 -223.904556)
		(end 58.133996 -223.904556)
		(width 0.18288)
		(layer "In4.Cu")
		(net "M_B_CPU1_SB_DQ<4>")
	)
	(segment
		(start 89.842086 -233.829098)
		(end 89.830148 -233.835956)
		(width 0.088646)
		(layer "In4.Cu")
		(net "M_B_CPU1_SB_DQ<4>")
	)
	(segment
		(start 88.902286 -233.829098)
		(end 88.897714 -233.831638)
		(width 0.088646)
		(layer "In4.Cu")
		(net "M_B_CPU1_SB_DQ<4>")
	)
	(arc
		(start 90.769948 -233.835956)
		(mid 90.490487 -233.907393)
		(end 90.212164 -233.831638)
		(width 0.088646)
		(layer "In4.Cu")
		(net "M_B_CPU1_SB_DQ<4>")
	)
	(arc
		(start 84.198968 -233.831892)
		(mid 84.158038 -233.858925)
		(end 84.12099 -233.891074)
		(width 0.088646)
		(layer "In4.Cu")
		(net "M_B_CPU1_SB_DQ<4>")
	)
	(arc
		(start 88.893142 -233.834432)
		(mid 88.612478 -233.90744)
		(end 88.332564 -233.831638)
		(width 0.088646)
		(layer "In4.Cu")
		(net "M_B_CPU1_SB_DQ<4>")
	)
	(arc
		(start 90.212164 -233.831638)
		(mid 90.02747 -233.781537)
		(end 89.842086 -233.829098)
		(width 0.088646)
		(layer "In4.Cu")
		(net "M_B_CPU1_SB_DQ<4>")
	)
	(arc
		(start 89.830148 -233.835956)
		(mid 89.550687 -233.907393)
		(end 89.272364 -233.831638)
		(width 0.088646)
		(layer "In4.Cu")
		(net "M_B_CPU1_SB_DQ<4>")
	)
	(arc
		(start 86.452964 -233.831892)
		(mid 86.265766 -233.781749)
		(end 86.078568 -233.831892)
		(width 0.088646)
		(layer "In4.Cu")
		(net "M_B_CPU1_SB_DQ<4>")
	)
	(arc
		(start 84.573364 -233.831892)
		(mid 84.386166 -233.781749)
		(end 84.198968 -233.831892)
		(width 0.088646)
		(layer "In4.Cu")
		(net "M_B_CPU1_SB_DQ<4>")
	)
	(arc
		(start 91.454732 -233.997246)
		(mid 91.413622 -233.980552)
		(end 91.374214 -233.960162)
		(width 0.088646)
		(layer "In4.Cu")
		(net "M_B_CPU1_SB_DQ<4>")
	)
	(arc
		(start 89.272364 -233.831638)
		(mid 89.08767 -233.781537)
		(end 88.902286 -233.829098)
		(width 0.088646)
		(layer "In4.Cu")
		(net "M_B_CPU1_SB_DQ<4>")
	)
	(arc
		(start 87.958168 -233.831892)
		(mid 87.675466 -233.907634)
		(end 87.392764 -233.831892)
		(width 0.088646)
		(layer "In4.Cu")
		(net "M_B_CPU1_SB_DQ<4>")
	)
	(arc
		(start 87.392764 -233.831892)
		(mid 87.205566 -233.781749)
		(end 87.018368 -233.831892)
		(width 0.088646)
		(layer "In4.Cu")
		(net "M_B_CPU1_SB_DQ<4>")
	)
	(arc
		(start 87.018368 -233.831892)
		(mid 86.735666 -233.907634)
		(end 86.452964 -233.831892)
		(width 0.088646)
		(layer "In4.Cu")
		(net "M_B_CPU1_SB_DQ<4>")
	)
	(arc
		(start 91.151964 -233.831638)
		(mid 90.96727 -233.781537)
		(end 90.781886 -233.829098)
		(width 0.088646)
		(layer "In4.Cu")
		(net "M_B_CPU1_SB_DQ<4>")
	)
	(arc
		(start 85.138768 -233.831892)
		(mid 84.856066 -233.907634)
		(end 84.573364 -233.831892)
		(width 0.088646)
		(layer "In4.Cu")
		(net "M_B_CPU1_SB_DQ<4>")
	)
	(arc
		(start 85.513164 -233.831892)
		(mid 85.325966 -233.781749)
		(end 85.138768 -233.831892)
		(width 0.088646)
		(layer "In4.Cu")
		(net "M_B_CPU1_SB_DQ<4>")
	)
	(arc
		(start 86.078568 -233.831892)
		(mid 85.795866 -233.907634)
		(end 85.513164 -233.831892)
		(width 0.088646)
		(layer "In4.Cu")
		(net "M_B_CPU1_SB_DQ<4>")
	)
	(arc
		(start 88.332564 -233.831892)
		(mid 88.145366 -233.781749)
		(end 87.958168 -233.831892)
		(width 0.088646)
		(layer "In4.Cu")
		(net "M_B_CPU1_SB_DQ<4>")
	)
	(segment
		(start 44.238926 -229.913434)
		(end 44.238926 -229.742746)
		(width 0.20066)
		(layer "F.Cu")
		(net "M_B_CPU1_SB_DQ<3>")
	)
	(segment
		(start 47.060358 -230.041704)
		(end 44.987464 -230.041704)
		(width 0.1016)
		(layer "F.Cu")
		(net "M_B_CPU1_SB_DQ<3>")
	)
	(segment
		(start 51.064414 -229.616762)
		(end 49.959514 -229.616762)
		(width 0.20066)
		(layer "F.Cu")
		(net "M_B_CPU1_SB_DQ<3>")
	)
	(segment
		(start 48.277526 -229.612444)
		(end 47.882302 -229.612444)
		(width 0.20066)
		(layer "F.Cu")
		(net "M_B_CPU1_SB_DQ<3>")
	)
	(segment
		(start 49.959514 -229.616762)
		(end 49.143412 -229.616762)
		(width 0.20066)
		(layer "F.Cu")
		(net "M_B_CPU1_SB_DQ<3>")
	)
	(segment
		(start 47.882302 -229.612444)
		(end 47.753778 -229.740968)
		(width 0.20066)
		(layer "F.Cu")
		(net "M_B_CPU1_SB_DQ<3>")
	)
	(segment
		(start 44.238926 -229.742746)
		(end 44.112942 -229.616762)
		(width 0.20066)
		(layer "F.Cu")
		(net "M_B_CPU1_SB_DQ<3>")
	)
	(segment
		(start 93.783912 -236.319822)
		(end 93.784166 -236.319568)
		(width 0.20066)
		(layer "F.Cu")
		(net "M_B_CPU1_SB_DQ<3>")
	)
	(segment
		(start 48.489362 -229.82428)
		(end 48.277526 -229.612444)
		(width 0.20066)
		(layer "F.Cu")
		(net "M_B_CPU1_SB_DQ<3>")
	)
	(segment
		(start 47.753778 -229.892606)
		(end 47.60468 -230.041704)
		(width 0.20066)
		(layer "F.Cu")
		(net "M_B_CPU1_SB_DQ<3>")
	)
	(segment
		(start 47.60468 -230.041704)
		(end 47.060358 -230.041704)
		(width 0.20066)
		(layer "F.Cu")
		(net "M_B_CPU1_SB_DQ<3>")
	)
	(segment
		(start 44.987464 -230.041704)
		(end 44.749466 -230.041704)
		(width 0.101854)
		(layer "F.Cu")
		(net "M_B_CPU1_SB_DQ<3>")
	)
	(segment
		(start 47.753778 -229.740968)
		(end 47.753778 -229.892606)
		(width 0.20066)
		(layer "F.Cu")
		(net "M_B_CPU1_SB_DQ<3>")
	)
	(segment
		(start 44.38142 -230.055928)
		(end 44.238926 -229.913434)
		(width 0.20066)
		(layer "F.Cu")
		(net "M_B_CPU1_SB_DQ<3>")
	)
	(segment
		(start 48.935894 -229.82428)
		(end 48.489362 -229.82428)
		(width 0.20066)
		(layer "F.Cu")
		(net "M_B_CPU1_SB_DQ<3>")
	)
	(segment
		(start 93.784166 -236.319568)
		(end 93.784166 -235.783882)
		(width 0.20066)
		(layer "F.Cu")
		(net "M_B_CPU1_SB_DQ<3>")
	)
	(segment
		(start 44.749466 -230.041704)
		(end 44.735242 -230.055928)
		(width 0.101854)
		(layer "F.Cu")
		(net "M_B_CPU1_SB_DQ<3>")
	)
	(segment
		(start 44.112942 -229.616762)
		(end 42.415714 -229.616762)
		(width 0.20066)
		(layer "F.Cu")
		(net "M_B_CPU1_SB_DQ<3>")
	)
	(segment
		(start 44.735242 -230.055928)
		(end 44.38142 -230.055928)
		(width 0.20066)
		(layer "F.Cu")
		(net "M_B_CPU1_SB_DQ<3>")
	)
	(segment
		(start 49.143412 -229.616762)
		(end 48.935894 -229.82428)
		(width 0.20066)
		(layer "F.Cu")
		(net "M_B_CPU1_SB_DQ<3>")
	)
	(segment
		(start 59.473846 -228.443536)
		(end 59.473846 -227.698046)
		(width 0.18288)
		(layer "In4.Cu")
		(net "M_B_CPU1_SB_DQ<3>")
	)
	(segment
		(start 52.860448 -229.17277)
		(end 51.96459 -229.17277)
		(width 0.18288)
		(layer "In4.Cu")
		(net "M_B_CPU1_SB_DQ<3>")
	)
	(segment
		(start 58.580782 -227.538026)
		(end 58.342276 -227.776532)
		(width 0.18288)
		(layer "In4.Cu")
		(net "M_B_CPU1_SB_DQ<3>")
	)
	(segment
		(start 63.119254 -227.88753)
		(end 62.794134 -227.88753)
		(width 0.18288)
		(layer "In4.Cu")
		(net "M_B_CPU1_SB_DQ<3>")
	)
	(segment
		(start 84.4042 -236.272324)
		(end 83.79968 -236.272324)
		(width 0.088646)
		(layer "In4.Cu")
		(net "M_B_CPU1_SB_DQ<3>")
	)
	(segment
		(start 58.342276 -228.035104)
		(end 58.397902 -228.09073)
		(width 0.18288)
		(layer "In4.Cu")
		(net "M_B_CPU1_SB_DQ<3>")
	)
	(segment
		(start 90.777314 -236.108494)
		(end 90.769948 -236.104176)
		(width 0.088646)
		(layer "In4.Cu")
		(net "M_B_CPU1_SB_DQ<3>")
	)
	(segment
		(start 83.565746 -236.03839)
		(end 82.708496 -236.03839)
		(width 0.088646)
		(layer "In4.Cu")
		(net "M_B_CPU1_SB_DQ<3>")
	)
	(segment
		(start 63.302134 -229.00894)
		(end 63.302134 -228.07041)
		(width 0.18288)
		(layer "In4.Cu")
		(net "M_B_CPU1_SB_DQ<3>")
	)
	(segment
		(start 51.520598 -229.616762)
		(end 51.064414 -229.616762)
		(width 0.18288)
		(layer "In4.Cu")
		(net "M_B_CPU1_SB_DQ<3>")
	)
	(segment
		(start 64.322452 -229.19182)
		(end 63.485014 -229.19182)
		(width 0.18288)
		(layer "In4.Cu")
		(net "M_B_CPU1_SB_DQ<3>")
	)
	(segment
		(start 51.96459 -229.17277)
		(end 51.520598 -229.616762)
		(width 0.18288)
		(layer "In4.Cu")
		(net "M_B_CPU1_SB_DQ<3>")
	)
	(segment
		(start 83.79968 -236.272324)
		(end 83.565746 -236.03839)
		(width 0.088646)
		(layer "In4.Cu")
		(net "M_B_CPU1_SB_DQ<3>")
	)
	(segment
		(start 55.892192 -229.218744)
		(end 55.339996 -228.666548)
		(width 0.18288)
		(layer "In4.Cu")
		(net "M_B_CPU1_SB_DQ<3>")
	)
	(segment
		(start 57.909206 -228.579426)
		(end 57.85358 -228.5238)
		(width 0.18288)
		(layer "In4.Cu")
		(net "M_B_CPU1_SB_DQ<3>")
	)
	(segment
		(start 60.327032 -227.683568)
		(end 60.167012 -227.843588)
		(width 0.18288)
		(layer "In4.Cu")
		(net "M_B_CPU1_SB_DQ<3>")
	)
	(segment
		(start 58.167778 -228.579426)
		(end 57.909206 -228.579426)
		(width 0.18288)
		(layer "In4.Cu")
		(net "M_B_CPU1_SB_DQ<3>")
	)
	(segment
		(start 90.781886 -236.111034)
		(end 90.777314 -236.108494)
		(width 0.088646)
		(layer "In4.Cu")
		(net "M_B_CPU1_SB_DQ<3>")
	)
	(segment
		(start 67.824096 -230.041704)
		(end 65.172336 -230.041704)
		(width 0.18288)
		(layer "In4.Cu")
		(net "M_B_CPU1_SB_DQ<3>")
	)
	(segment
		(start 57.595008 -228.5238)
		(end 56.900064 -229.218744)
		(width 0.18288)
		(layer "In4.Cu")
		(net "M_B_CPU1_SB_DQ<3>")
	)
	(segment
		(start 59.313826 -227.538026)
		(end 58.580782 -227.538026)
		(width 0.18288)
		(layer "In4.Cu")
		(net "M_B_CPU1_SB_DQ<3>")
	)
	(segment
		(start 91.501722 -235.656628)
		(end 91.46286 -235.750608)
		(width 0.088646)
		(layer "In4.Cu")
		(net "M_B_CPU1_SB_DQ<3>")
	)
	(segment
		(start 84.541614 -236.13491)
		(end 84.4042 -236.272324)
		(width 0.088646)
		(layer "In4.Cu")
		(net "M_B_CPU1_SB_DQ<3>")
	)
	(segment
		(start 59.659012 -228.628702)
		(end 59.473846 -228.443536)
		(width 0.18288)
		(layer "In4.Cu")
		(net "M_B_CPU1_SB_DQ<3>")
	)
	(segment
		(start 59.473846 -227.698046)
		(end 59.313826 -227.538026)
		(width 0.18288)
		(layer "In4.Cu")
		(net "M_B_CPU1_SB_DQ<3>")
	)
	(segment
		(start 53.024024 -229.336346)
		(end 52.860448 -229.17277)
		(width 0.18288)
		(layer "In4.Cu")
		(net "M_B_CPU1_SB_DQ<3>")
	)
	(segment
		(start 89.842086 -236.111034)
		(end 89.830148 -236.104176)
		(width 0.088646)
		(layer "In4.Cu")
		(net "M_B_CPU1_SB_DQ<3>")
	)
	(segment
		(start 55.339996 -228.666548)
		(end 54.012338 -228.666548)
		(width 0.18288)
		(layer "In4.Cu")
		(net "M_B_CPU1_SB_DQ<3>")
	)
	(segment
		(start 93.784166 -235.783882)
		(end 93.783912 -235.783882)
		(width 0.088646)
		(layer "In4.Cu")
		(net "M_B_CPU1_SB_DQ<3>")
	)
	(segment
		(start 91.722956 -235.456222)
		(end 91.711272 -235.462826)
		(width 0.088646)
		(layer "In4.Cu")
		(net "M_B_CPU1_SB_DQ<3>")
	)
	(segment
		(start 63.302134 -228.07041)
		(end 63.119254 -227.88753)
		(width 0.18288)
		(layer "In4.Cu")
		(net "M_B_CPU1_SB_DQ<3>")
	)
	(segment
		(start 93.428312 -235.688632)
		(end 93.031564 -235.459524)
		(width 0.088646)
		(layer "In4.Cu")
		(net "M_B_CPU1_SB_DQ<3>")
	)
	(segment
		(start 82.708496 -236.03839)
		(end 73.820782 -236.03839)
		(width 0.18288)
		(layer "In4.Cu")
		(net "M_B_CPU1_SB_DQ<3>")
	)
	(segment
		(start 58.342276 -227.776532)
		(end 58.342276 -228.035104)
		(width 0.18288)
		(layer "In4.Cu")
		(net "M_B_CPU1_SB_DQ<3>")
	)
	(segment
		(start 92.662756 -235.456222)
		(end 92.651072 -235.462826)
		(width 0.088646)
		(layer "In4.Cu")
		(net "M_B_CPU1_SB_DQ<3>")
	)
	(segment
		(start 63.485014 -229.19182)
		(end 63.302134 -229.00894)
		(width 0.18288)
		(layer "In4.Cu")
		(net "M_B_CPU1_SB_DQ<3>")
	)
	(segment
		(start 60.167012 -227.843588)
		(end 60.167012 -228.468682)
		(width 0.18288)
		(layer "In4.Cu")
		(net "M_B_CPU1_SB_DQ<3>")
	)
	(segment
		(start 62.428374 -229.19182)
		(end 61.629036 -229.19182)
		(width 0.18288)
		(layer "In4.Cu")
		(net "M_B_CPU1_SB_DQ<3>")
	)
	(segment
		(start 65.172336 -230.041704)
		(end 64.322452 -229.19182)
		(width 0.18288)
		(layer "In4.Cu")
		(net "M_B_CPU1_SB_DQ<3>")
	)
	(segment
		(start 54.012338 -228.666548)
		(end 53.34254 -229.336346)
		(width 0.18288)
		(layer "In4.Cu")
		(net "M_B_CPU1_SB_DQ<3>")
	)
	(segment
		(start 91.591384 -235.554774)
		(end 91.52636 -235.620052)
		(width 0.088646)
		(layer "In4.Cu")
		(net "M_B_CPU1_SB_DQ<3>")
	)
	(segment
		(start 60.79998 -227.683568)
		(end 60.327032 -227.683568)
		(width 0.18288)
		(layer "In4.Cu")
		(net "M_B_CPU1_SB_DQ<3>")
	)
	(segment
		(start 60.006992 -228.628702)
		(end 59.659012 -228.628702)
		(width 0.18288)
		(layer "In4.Cu")
		(net "M_B_CPU1_SB_DQ<3>")
	)
	(segment
		(start 62.611254 -229.00894)
		(end 62.428374 -229.19182)
		(width 0.18288)
		(layer "In4.Cu")
		(net "M_B_CPU1_SB_DQ<3>")
	)
	(segment
		(start 73.820782 -236.03839)
		(end 67.824096 -230.041704)
		(width 0.18288)
		(layer "In4.Cu")
		(net "M_B_CPU1_SB_DQ<3>")
	)
	(segment
		(start 88.897714 -236.108494)
		(end 88.893142 -236.1057)
		(width 0.088646)
		(layer "In4.Cu")
		(net "M_B_CPU1_SB_DQ<3>")
	)
	(segment
		(start 61.629036 -229.19182)
		(end 60.95238 -228.515164)
		(width 0.18288)
		(layer "In4.Cu")
		(net "M_B_CPU1_SB_DQ<3>")
	)
	(segment
		(start 60.95238 -227.835968)
		(end 60.79998 -227.683568)
		(width 0.18288)
		(layer "In4.Cu")
		(net "M_B_CPU1_SB_DQ<3>")
	)
	(segment
		(start 56.900064 -229.218744)
		(end 55.892192 -229.218744)
		(width 0.18288)
		(layer "In4.Cu")
		(net "M_B_CPU1_SB_DQ<3>")
	)
	(segment
		(start 53.34254 -229.336346)
		(end 53.024024 -229.336346)
		(width 0.18288)
		(layer "In4.Cu")
		(net "M_B_CPU1_SB_DQ<3>")
	)
	(segment
		(start 60.167012 -228.468682)
		(end 60.006992 -228.628702)
		(width 0.18288)
		(layer "In4.Cu")
		(net "M_B_CPU1_SB_DQ<3>")
	)
	(segment
		(start 62.611254 -228.07041)
		(end 62.611254 -229.00894)
		(width 0.18288)
		(layer "In4.Cu")
		(net "M_B_CPU1_SB_DQ<3>")
	)
	(segment
		(start 88.332564 -236.108494)
		(end 88.332564 -236.10824)
		(width 0.088646)
		(layer "In4.Cu")
		(net "M_B_CPU1_SB_DQ<3>")
	)
	(segment
		(start 60.95238 -228.515164)
		(end 60.95238 -227.835968)
		(width 0.18288)
		(layer "In4.Cu")
		(net "M_B_CPU1_SB_DQ<3>")
	)
	(segment
		(start 62.794134 -227.88753)
		(end 62.611254 -228.07041)
		(width 0.18288)
		(layer "In4.Cu")
		(net "M_B_CPU1_SB_DQ<3>")
	)
	(segment
		(start 88.902286 -236.111034)
		(end 88.897714 -236.108494)
		(width 0.088646)
		(layer "In4.Cu")
		(net "M_B_CPU1_SB_DQ<3>")
	)
	(segment
		(start 58.397902 -228.349302)
		(end 58.167778 -228.579426)
		(width 0.18288)
		(layer "In4.Cu")
		(net "M_B_CPU1_SB_DQ<3>")
	)
	(segment
		(start 91.301062 -235.99267)
		(end 91.295728 -235.998004)
		(width 0.088646)
		(layer "In4.Cu")
		(net "M_B_CPU1_SB_DQ<3>")
	)
	(segment
		(start 58.397902 -228.09073)
		(end 58.397902 -228.349302)
		(width 0.18288)
		(layer "In4.Cu")
		(net "M_B_CPU1_SB_DQ<3>")
	)
	(segment
		(start 57.85358 -228.5238)
		(end 57.595008 -228.5238)
		(width 0.18288)
		(layer "In4.Cu")
		(net "M_B_CPU1_SB_DQ<3>")
	)
	(arc
		(start 90.212164 -236.108494)
		(mid 90.02747 -236.158595)
		(end 89.842086 -236.111034)
		(width 0.088646)
		(layer "In4.Cu")
		(net "M_B_CPU1_SB_DQ<3>")
	)
	(arc
		(start 91.295728 -235.998004)
		(mid 91.227478 -236.057976)
		(end 91.151964 -236.108494)
		(width 0.088646)
		(layer "In4.Cu")
		(net "M_B_CPU1_SB_DQ<3>")
	)
	(arc
		(start 85.138768 -236.10824)
		(mid 84.880011 -236.032889)
		(end 84.615782 -236.085888)
		(width 0.088646)
		(layer "In4.Cu")
		(net "M_B_CPU1_SB_DQ<3>")
	)
	(arc
		(start 91.46286 -235.750608)
		(mid 91.393904 -235.879623)
		(end 91.301062 -235.99267)
		(width 0.088646)
		(layer "In4.Cu")
		(net "M_B_CPU1_SB_DQ<3>")
	)
	(arc
		(start 88.332564 -236.10824)
		(mid 88.145366 -236.158383)
		(end 87.958168 -236.10824)
		(width 0.088646)
		(layer "In4.Cu")
		(net "M_B_CPU1_SB_DQ<3>")
	)
	(arc
		(start 84.615782 -236.085888)
		(mid 84.576927 -236.107717)
		(end 84.541614 -236.13491)
		(width 0.088646)
		(layer "In4.Cu")
		(net "M_B_CPU1_SB_DQ<3>")
	)
	(arc
		(start 89.272364 -236.108494)
		(mid 89.08767 -236.158595)
		(end 88.902286 -236.111034)
		(width 0.088646)
		(layer "In4.Cu")
		(net "M_B_CPU1_SB_DQ<3>")
	)
	(arc
		(start 93.783912 -235.783882)
		(mid 93.599827 -235.759704)
		(end 93.428312 -235.688632)
		(width 0.088646)
		(layer "In4.Cu")
		(net "M_B_CPU1_SB_DQ<3>")
	)
	(arc
		(start 88.893142 -236.1057)
		(mid 88.612478 -236.032692)
		(end 88.332564 -236.108494)
		(width 0.088646)
		(layer "In4.Cu")
		(net "M_B_CPU1_SB_DQ<3>")
	)
	(arc
		(start 91.52636 -235.620052)
		(mid 91.512221 -235.637116)
		(end 91.501722 -235.656628)
		(width 0.088646)
		(layer "In4.Cu")
		(net "M_B_CPU1_SB_DQ<3>")
	)
	(arc
		(start 85.513164 -236.10824)
		(mid 85.325966 -236.158383)
		(end 85.138768 -236.10824)
		(width 0.088646)
		(layer "In4.Cu")
		(net "M_B_CPU1_SB_DQ<3>")
	)
	(arc
		(start 86.078568 -236.10824)
		(mid 85.795866 -236.032498)
		(end 85.513164 -236.10824)
		(width 0.088646)
		(layer "In4.Cu")
		(net "M_B_CPU1_SB_DQ<3>")
	)
	(arc
		(start 87.958168 -236.10824)
		(mid 87.675466 -236.032498)
		(end 87.392764 -236.10824)
		(width 0.088646)
		(layer "In4.Cu")
		(net "M_B_CPU1_SB_DQ<3>")
	)
	(arc
		(start 90.769948 -236.104176)
		(mid 90.490487 -236.032739)
		(end 90.212164 -236.108494)
		(width 0.088646)
		(layer "In4.Cu")
		(net "M_B_CPU1_SB_DQ<3>")
	)
	(arc
		(start 91.711272 -235.462826)
		(mid 91.648313 -235.504869)
		(end 91.591384 -235.554774)
		(width 0.088646)
		(layer "In4.Cu")
		(net "M_B_CPU1_SB_DQ<3>")
	)
	(arc
		(start 92.651072 -235.462826)
		(mid 92.370967 -235.535268)
		(end 92.091764 -235.459524)
		(width 0.088646)
		(layer "In4.Cu")
		(net "M_B_CPU1_SB_DQ<3>")
	)
	(arc
		(start 86.452964 -236.10824)
		(mid 86.265766 -236.158383)
		(end 86.078568 -236.10824)
		(width 0.088646)
		(layer "In4.Cu")
		(net "M_B_CPU1_SB_DQ<3>")
	)
	(arc
		(start 89.830148 -236.104176)
		(mid 89.550687 -236.032739)
		(end 89.272364 -236.108494)
		(width 0.088646)
		(layer "In4.Cu")
		(net "M_B_CPU1_SB_DQ<3>")
	)
	(arc
		(start 87.018368 -236.10824)
		(mid 86.735666 -236.032498)
		(end 86.452964 -236.10824)
		(width 0.088646)
		(layer "In4.Cu")
		(net "M_B_CPU1_SB_DQ<3>")
	)
	(arc
		(start 87.392764 -236.10824)
		(mid 87.205566 -236.158383)
		(end 87.018368 -236.10824)
		(width 0.088646)
		(layer "In4.Cu")
		(net "M_B_CPU1_SB_DQ<3>")
	)
	(arc
		(start 92.091764 -235.459524)
		(mid 91.90781 -235.409395)
		(end 91.722956 -235.456222)
		(width 0.088646)
		(layer "In4.Cu")
		(net "M_B_CPU1_SB_DQ<3>")
	)
	(arc
		(start 91.151964 -236.108494)
		(mid 90.96727 -236.158595)
		(end 90.781886 -236.111034)
		(width 0.088646)
		(layer "In4.Cu")
		(net "M_B_CPU1_SB_DQ<3>")
	)
	(arc
		(start 93.031564 -235.459524)
		(mid 92.84761 -235.409395)
		(end 92.662756 -235.456222)
		(width 0.088646)
		(layer "In4.Cu")
		(net "M_B_CPU1_SB_DQ<3>")
	)
	(segment
		(start 44.38142 -196.055742)
		(end 44.238926 -195.913248)
		(width 0.20066)
		(layer "F.Cu")
		(net "M_B_CPU1_SB_DQ<31>")
	)
	(segment
		(start 51.064414 -195.616576)
		(end 49.959514 -195.616576)
		(width 0.20066)
		(layer "F.Cu")
		(net "M_B_CPU1_SB_DQ<31>")
	)
	(segment
		(start 47.753778 -195.89242)
		(end 47.60468 -196.041518)
		(width 0.20066)
		(layer "F.Cu")
		(net "M_B_CPU1_SB_DQ<31>")
	)
	(segment
		(start 87.205312 -224.925382)
		(end 87.205312 -224.389696)
		(width 0.20066)
		(layer "F.Cu")
		(net "M_B_CPU1_SB_DQ<31>")
	)
	(segment
		(start 47.60468 -196.041518)
		(end 47.060358 -196.041518)
		(width 0.20066)
		(layer "F.Cu")
		(net "M_B_CPU1_SB_DQ<31>")
	)
	(segment
		(start 49.959514 -195.616576)
		(end 49.143412 -195.616576)
		(width 0.20066)
		(layer "F.Cu")
		(net "M_B_CPU1_SB_DQ<31>")
	)
	(segment
		(start 44.238926 -195.74256)
		(end 44.112942 -195.616576)
		(width 0.20066)
		(layer "F.Cu")
		(net "M_B_CPU1_SB_DQ<31>")
	)
	(segment
		(start 44.987464 -196.041518)
		(end 44.749466 -196.041518)
		(width 0.101854)
		(layer "F.Cu")
		(net "M_B_CPU1_SB_DQ<31>")
	)
	(segment
		(start 47.882302 -195.612258)
		(end 47.753778 -195.740782)
		(width 0.20066)
		(layer "F.Cu")
		(net "M_B_CPU1_SB_DQ<31>")
	)
	(segment
		(start 44.735242 -196.055742)
		(end 44.38142 -196.055742)
		(width 0.20066)
		(layer "F.Cu")
		(net "M_B_CPU1_SB_DQ<31>")
	)
	(segment
		(start 44.238926 -195.913248)
		(end 44.238926 -195.74256)
		(width 0.20066)
		(layer "F.Cu")
		(net "M_B_CPU1_SB_DQ<31>")
	)
	(segment
		(start 48.277526 -195.612258)
		(end 47.882302 -195.612258)
		(width 0.20066)
		(layer "F.Cu")
		(net "M_B_CPU1_SB_DQ<31>")
	)
	(segment
		(start 49.143412 -195.616576)
		(end 48.935894 -195.824094)
		(width 0.20066)
		(layer "F.Cu")
		(net "M_B_CPU1_SB_DQ<31>")
	)
	(segment
		(start 44.112942 -195.616576)
		(end 42.415714 -195.616576)
		(width 0.20066)
		(layer "F.Cu")
		(net "M_B_CPU1_SB_DQ<31>")
	)
	(segment
		(start 47.060358 -196.041518)
		(end 44.987464 -196.041518)
		(width 0.1016)
		(layer "F.Cu")
		(net "M_B_CPU1_SB_DQ<31>")
	)
	(segment
		(start 47.753778 -195.740782)
		(end 47.753778 -195.89242)
		(width 0.20066)
		(layer "F.Cu")
		(net "M_B_CPU1_SB_DQ<31>")
	)
	(segment
		(start 87.205312 -224.389696)
		(end 87.205566 -224.389442)
		(width 0.20066)
		(layer "F.Cu")
		(net "M_B_CPU1_SB_DQ<31>")
	)
	(segment
		(start 44.749466 -196.041518)
		(end 44.735242 -196.055742)
		(width 0.101854)
		(layer "F.Cu")
		(net "M_B_CPU1_SB_DQ<31>")
	)
	(segment
		(start 48.935894 -195.824094)
		(end 48.489362 -195.824094)
		(width 0.20066)
		(layer "F.Cu")
		(net "M_B_CPU1_SB_DQ<31>")
	)
	(segment
		(start 48.489362 -195.824094)
		(end 48.277526 -195.612258)
		(width 0.20066)
		(layer "F.Cu")
		(net "M_B_CPU1_SB_DQ<31>")
	)
	(segment
		(start 65.350898 -195.872354)
		(end 65.054226 -196.169026)
		(width 0.18288)
		(layer "In4.Cu")
		(net "M_B_CPU1_SB_DQ<31>")
	)
	(segment
		(start 83.986624 -221.534228)
		(end 83.660742 -221.208092)
		(width 0.088646)
		(layer "In4.Cu")
		(net "M_B_CPU1_SB_DQ<31>")
	)
	(segment
		(start 66.344038 -195.872354)
		(end 65.350898 -195.872354)
		(width 0.18288)
		(layer "In4.Cu")
		(net "M_B_CPU1_SB_DQ<31>")
	)
	(segment
		(start 81.678018 -220.770704)
		(end 78.229714 -217.3224)
		(width 0.18288)
		(layer "In4.Cu")
		(net "M_B_CPU1_SB_DQ<31>")
	)
	(segment
		(start 64.600074 -196.169026)
		(end 64.294004 -195.862956)
		(width 0.18288)
		(layer "In4.Cu")
		(net "M_B_CPU1_SB_DQ<31>")
	)
	(segment
		(start 56.683148 -195.804536)
		(end 55.65013 -195.804536)
		(width 0.18288)
		(layer "In4.Cu")
		(net "M_B_CPU1_SB_DQ<31>")
	)
	(segment
		(start 85.700362 -222.769176)
		(end 85.700362 -222.761556)
		(width 0.088646)
		(layer "In4.Cu")
		(net "M_B_CPU1_SB_DQ<31>")
	)
	(segment
		(start 61.383672 -196.169026)
		(end 61.200792 -195.986146)
		(width 0.18288)
		(layer "In4.Cu")
		(net "M_B_CPU1_SB_DQ<31>")
	)
	(segment
		(start 86.170516 -223.585532)
		(end 86.170516 -223.575626)
		(width 0.088646)
		(layer "In4.Cu")
		(net "M_B_CPU1_SB_DQ<31>")
	)
	(segment
		(start 51.571144 -196.123306)
		(end 51.064414 -195.616576)
		(width 0.18288)
		(layer "In4.Cu")
		(net "M_B_CPU1_SB_DQ<31>")
	)
	(segment
		(start 55.33136 -196.123306)
		(end 54.02707 -196.123306)
		(width 0.18288)
		(layer "In4.Cu")
		(net "M_B_CPU1_SB_DQ<31>")
	)
	(segment
		(start 55.65013 -195.804536)
		(end 55.33136 -196.123306)
		(width 0.18288)
		(layer "In4.Cu")
		(net "M_B_CPU1_SB_DQ<31>")
	)
	(segment
		(start 72.556116 -203.625196)
		(end 68.515738 -199.584818)
		(width 0.18288)
		(layer "In4.Cu")
		(net "M_B_CPU1_SB_DQ<31>")
	)
	(segment
		(start 60.509912 -195.986146)
		(end 60.327032 -196.169026)
		(width 0.18288)
		(layer "In4.Cu")
		(net "M_B_CPU1_SB_DQ<31>")
	)
	(segment
		(start 78.229714 -217.3224)
		(end 72.556116 -203.625196)
		(width 0.18288)
		(layer "In4.Cu")
		(net "M_B_CPU1_SB_DQ<31>")
	)
	(segment
		(start 53.330348 -195.831968)
		(end 53.03901 -196.123306)
		(width 0.18288)
		(layer "In4.Cu")
		(net "M_B_CPU1_SB_DQ<31>")
	)
	(segment
		(start 58.219594 -195.827142)
		(end 57.666382 -196.380354)
		(width 0.18288)
		(layer "In4.Cu")
		(net "M_B_CPU1_SB_DQ<31>")
	)
	(segment
		(start 60.509912 -195.908422)
		(end 60.509912 -195.986146)
		(width 0.18288)
		(layer "In4.Cu")
		(net "M_B_CPU1_SB_DQ<31>")
	)
	(segment
		(start 82.708496 -220.770704)
		(end 81.678018 -220.770704)
		(width 0.18288)
		(layer "In4.Cu")
		(net "M_B_CPU1_SB_DQ<31>")
	)
	(segment
		(start 87.049102 -224.118424)
		(end 86.959948 -224.094548)
		(width 0.088646)
		(layer "In4.Cu")
		(net "M_B_CPU1_SB_DQ<31>")
	)
	(segment
		(start 63.033402 -195.862956)
		(end 62.727332 -196.169026)
		(width 0.18288)
		(layer "In4.Cu")
		(net "M_B_CPU1_SB_DQ<31>")
	)
	(segment
		(start 85.230716 -221.963234)
		(end 85.230716 -221.94774)
		(width 0.088646)
		(layer "In4.Cu")
		(net "M_B_CPU1_SB_DQ<31>")
	)
	(segment
		(start 57.258966 -196.380354)
		(end 56.683148 -195.804536)
		(width 0.18288)
		(layer "In4.Cu")
		(net "M_B_CPU1_SB_DQ<31>")
	)
	(segment
		(start 60.327032 -196.169026)
		(end 59.61507 -196.169026)
		(width 0.18288)
		(layer "In4.Cu")
		(net "M_B_CPU1_SB_DQ<31>")
	)
	(segment
		(start 85.5218 -222.442278)
		(end 85.51291 -222.437198)
		(width 0.088646)
		(layer "In4.Cu")
		(net "M_B_CPU1_SB_DQ<31>")
	)
	(segment
		(start 87.205566 -224.389442)
		(end 87.049102 -224.118424)
		(width 0.088646)
		(layer "In4.Cu")
		(net "M_B_CPU1_SB_DQ<31>")
	)
	(segment
		(start 57.666382 -196.380354)
		(end 57.258966 -196.380354)
		(width 0.18288)
		(layer "In4.Cu")
		(net "M_B_CPU1_SB_DQ<31>")
	)
	(segment
		(start 61.017912 -195.725542)
		(end 60.692792 -195.725542)
		(width 0.18288)
		(layer "In4.Cu")
		(net "M_B_CPU1_SB_DQ<31>")
	)
	(segment
		(start 53.735732 -195.831968)
		(end 53.330348 -195.831968)
		(width 0.18288)
		(layer "In4.Cu")
		(net "M_B_CPU1_SB_DQ<31>")
	)
	(segment
		(start 67.426332 -196.954648)
		(end 66.344038 -195.872354)
		(width 0.18288)
		(layer "In4.Cu")
		(net "M_B_CPU1_SB_DQ<31>")
	)
	(segment
		(start 83.223354 -220.770704)
		(end 82.708496 -220.770704)
		(width 0.088646)
		(layer "In4.Cu")
		(net "M_B_CPU1_SB_DQ<31>")
	)
	(segment
		(start 85.052154 -221.628462)
		(end 85.043264 -221.623382)
		(width 0.088646)
		(layer "In4.Cu")
		(net "M_B_CPU1_SB_DQ<31>")
	)
	(segment
		(start 65.054226 -196.169026)
		(end 64.600074 -196.169026)
		(width 0.18288)
		(layer "In4.Cu")
		(net "M_B_CPU1_SB_DQ<31>")
	)
	(segment
		(start 64.294004 -195.862956)
		(end 63.033402 -195.862956)
		(width 0.18288)
		(layer "In4.Cu")
		(net "M_B_CPU1_SB_DQ<31>")
	)
	(segment
		(start 68.515738 -199.584818)
		(end 67.426332 -196.954648)
		(width 0.18288)
		(layer "In4.Cu")
		(net "M_B_CPU1_SB_DQ<31>")
	)
	(segment
		(start 59.61507 -196.169026)
		(end 59.273186 -195.827142)
		(width 0.18288)
		(layer "In4.Cu")
		(net "M_B_CPU1_SB_DQ<31>")
	)
	(segment
		(start 60.692792 -195.725542)
		(end 60.509912 -195.908422)
		(width 0.18288)
		(layer "In4.Cu")
		(net "M_B_CPU1_SB_DQ<31>")
	)
	(segment
		(start 61.200792 -195.986146)
		(end 61.200792 -195.908422)
		(width 0.18288)
		(layer "In4.Cu")
		(net "M_B_CPU1_SB_DQ<31>")
	)
	(segment
		(start 83.660742 -221.208092)
		(end 83.223354 -220.770704)
		(width 0.088646)
		(layer "In4.Cu")
		(net "M_B_CPU1_SB_DQ<31>")
	)
	(segment
		(start 61.200792 -195.908422)
		(end 61.017912 -195.725542)
		(width 0.18288)
		(layer "In4.Cu")
		(net "M_B_CPU1_SB_DQ<31>")
	)
	(segment
		(start 59.273186 -195.827142)
		(end 58.219594 -195.827142)
		(width 0.18288)
		(layer "In4.Cu")
		(net "M_B_CPU1_SB_DQ<31>")
	)
	(segment
		(start 62.727332 -196.169026)
		(end 61.383672 -196.169026)
		(width 0.18288)
		(layer "In4.Cu")
		(net "M_B_CPU1_SB_DQ<31>")
	)
	(segment
		(start 54.02707 -196.123306)
		(end 53.735732 -195.831968)
		(width 0.18288)
		(layer "In4.Cu")
		(net "M_B_CPU1_SB_DQ<31>")
	)
	(segment
		(start 53.03901 -196.123306)
		(end 51.571144 -196.123306)
		(width 0.18288)
		(layer "In4.Cu")
		(net "M_B_CPU1_SB_DQ<31>")
	)
	(segment
		(start 85.991954 -223.256348)
		(end 85.983064 -223.251268)
		(width 0.088646)
		(layer "In4.Cu")
		(net "M_B_CPU1_SB_DQ<31>")
	)
	(arc
		(start 86.452964 -224.065084)
		(mid 86.248629 -223.862479)
		(end 86.170516 -223.585532)
		(width 0.088646)
		(layer "In4.Cu")
		(net "M_B_CPU1_SB_DQ<31>")
	)
	(arc
		(start 85.51291 -222.437198)
		(mid 85.310087 -222.236967)
		(end 85.230716 -221.963234)
		(width 0.088646)
		(layer "In4.Cu")
		(net "M_B_CPU1_SB_DQ<31>")
	)
	(arc
		(start 85.700362 -222.761556)
		(mid 85.652683 -222.578656)
		(end 85.5218 -222.442278)
		(width 0.088646)
		(layer "In4.Cu")
		(net "M_B_CPU1_SB_DQ<31>")
	)
	(arc
		(start 85.043264 -221.623382)
		(mid 84.856066 -221.573239)
		(end 84.668868 -221.623382)
		(width 0.088646)
		(layer "In4.Cu")
		(net "M_B_CPU1_SB_DQ<31>")
	)
	(arc
		(start 84.103464 -221.623382)
		(mid 84.070728 -221.603011)
		(end 84.039456 -221.580456)
		(width 0.088646)
		(layer "In4.Cu")
		(net "M_B_CPU1_SB_DQ<31>")
	)
	(arc
		(start 84.039456 -221.580456)
		(mid 84.01232 -221.558164)
		(end 83.986624 -221.534228)
		(width 0.088646)
		(layer "In4.Cu")
		(net "M_B_CPU1_SB_DQ<31>")
	)
	(arc
		(start 85.983064 -223.251268)
		(mid 85.777992 -223.047589)
		(end 85.700362 -222.769176)
		(width 0.088646)
		(layer "In4.Cu")
		(net "M_B_CPU1_SB_DQ<31>")
	)
	(arc
		(start 86.170516 -223.575626)
		(mid 86.122837 -223.392726)
		(end 85.991954 -223.256348)
		(width 0.088646)
		(layer "In4.Cu")
		(net "M_B_CPU1_SB_DQ<31>")
	)
	(arc
		(start 86.959948 -224.094548)
		(mid 86.702949 -224.139995)
		(end 86.452964 -224.065084)
		(width 0.088646)
		(layer "In4.Cu")
		(net "M_B_CPU1_SB_DQ<31>")
	)
	(arc
		(start 84.668868 -221.623382)
		(mid 84.386166 -221.699158)
		(end 84.103464 -221.623382)
		(width 0.088646)
		(layer "In4.Cu")
		(net "M_B_CPU1_SB_DQ<31>")
	)
	(arc
		(start 85.230716 -221.94774)
		(mid 85.183037 -221.76484)
		(end 85.052154 -221.628462)
		(width 0.088646)
		(layer "In4.Cu")
		(net "M_B_CPU1_SB_DQ<31>")
	)
	(segment
		(start 48.64481 -197.316598)
		(end 48.432974 -197.528434)
		(width 0.20066)
		(layer "F.Cu")
		(net "M_B_CPU1_SB_DQ<30>")
	)
	(segment
		(start 43.562778 -197.316598)
		(end 42.415714 -197.316598)
		(width 0.20066)
		(layer "F.Cu")
		(net "M_B_CPU1_SB_DQ<30>")
	)
	(segment
		(start 51.064414 -197.316598)
		(end 49.959514 -197.316598)
		(width 0.20066)
		(layer "F.Cu")
		(net "M_B_CPU1_SB_DQ<30>")
	)
	(segment
		(start 48.004476 -197.528434)
		(end 47.83709 -197.361048)
		(width 0.20066)
		(layer "F.Cu")
		(net "M_B_CPU1_SB_DQ<30>")
	)
	(segment
		(start 47.83709 -197.03542)
		(end 47.693326 -196.891656)
		(width 0.20066)
		(layer "F.Cu")
		(net "M_B_CPU1_SB_DQ<30>")
	)
	(segment
		(start 43.99788 -196.881496)
		(end 43.562778 -197.316598)
		(width 0.20066)
		(layer "F.Cu")
		(net "M_B_CPU1_SB_DQ<30>")
	)
	(segment
		(start 44.735242 -196.881496)
		(end 43.99788 -196.881496)
		(width 0.20066)
		(layer "F.Cu")
		(net "M_B_CPU1_SB_DQ<30>")
	)
	(segment
		(start 47.060358 -196.891656)
		(end 45.000418 -196.891656)
		(width 0.1016)
		(layer "F.Cu")
		(net "M_B_CPU1_SB_DQ<30>")
	)
	(segment
		(start 45.000418 -196.891656)
		(end 44.745402 -196.891656)
		(width 0.101854)
		(layer "F.Cu")
		(net "M_B_CPU1_SB_DQ<30>")
	)
	(segment
		(start 47.83709 -197.361048)
		(end 47.83709 -197.03542)
		(width 0.20066)
		(layer "F.Cu")
		(net "M_B_CPU1_SB_DQ<30>")
	)
	(segment
		(start 44.745402 -196.891656)
		(end 44.735242 -196.881496)
		(width 0.101854)
		(layer "F.Cu")
		(net "M_B_CPU1_SB_DQ<30>")
	)
	(segment
		(start 85.325712 -224.925382)
		(end 85.325712 -224.389442)
		(width 0.20066)
		(layer "F.Cu")
		(net "M_B_CPU1_SB_DQ<30>")
	)
	(segment
		(start 48.432974 -197.528434)
		(end 48.004476 -197.528434)
		(width 0.20066)
		(layer "F.Cu")
		(net "M_B_CPU1_SB_DQ<30>")
	)
	(segment
		(start 49.959514 -197.316598)
		(end 48.64481 -197.316598)
		(width 0.20066)
		(layer "F.Cu")
		(net "M_B_CPU1_SB_DQ<30>")
	)
	(segment
		(start 47.693326 -196.891656)
		(end 47.060358 -196.891656)
		(width 0.20066)
		(layer "F.Cu")
		(net "M_B_CPU1_SB_DQ<30>")
	)
	(segment
		(start 57.86755 -197.720204)
		(end 57.86755 -197.884542)
		(width 0.18288)
		(layer "In4.Cu")
		(net "M_B_CPU1_SB_DQ<30>")
	)
	(segment
		(start 53.816504 -197.996048)
		(end 53.633624 -197.813168)
		(width 0.18288)
		(layer "In4.Cu")
		(net "M_B_CPU1_SB_DQ<30>")
	)
	(segment
		(start 67.250056 -199.297544)
		(end 66.987928 -199.035416)
		(width 0.18288)
		(layer "In4.Cu")
		(net "M_B_CPU1_SB_DQ<30>")
	)
	(segment
		(start 52.942744 -198.763636)
		(end 52.643532 -198.763636)
		(width 0.18288)
		(layer "In4.Cu")
		(net "M_B_CPU1_SB_DQ<30>")
	)
	(segment
		(start 56.99379 -197.537324)
		(end 56.30291 -197.537324)
		(width 0.18288)
		(layer "In4.Cu")
		(net "M_B_CPU1_SB_DQ<30>")
	)
	(segment
		(start 65.567052 -197.883272)
		(end 65.344802 -197.661022)
		(width 0.18288)
		(layer "In4.Cu")
		(net "M_B_CPU1_SB_DQ<30>")
	)
	(segment
		(start 61.691266 -197.771512)
		(end 61.30925 -197.389496)
		(width 0.18288)
		(layer "In4.Cu")
		(net "M_B_CPU1_SB_DQ<30>")
	)
	(segment
		(start 66.987928 -199.035416)
		(end 66.792856 -199.035416)
		(width 0.18288)
		(layer "In4.Cu")
		(net "M_B_CPU1_SB_DQ<30>")
	)
	(segment
		(start 66.298318 -198.799196)
		(end 66.043556 -198.799196)
		(width 0.18288)
		(layer "In4.Cu")
		(net "M_B_CPU1_SB_DQ<30>")
	)
	(segment
		(start 77.43952 -218.017344)
		(end 71.728076 -204.228954)
		(width 0.18288)
		(layer "In4.Cu")
		(net "M_B_CPU1_SB_DQ<30>")
	)
	(segment
		(start 84.582 -222.442278)
		(end 84.57311 -222.437198)
		(width 0.088646)
		(layer "In4.Cu")
		(net "M_B_CPU1_SB_DQ<30>")
	)
	(segment
		(start 84.760562 -222.77578)
		(end 84.760562 -222.761556)
		(width 0.088646)
		(layer "In4.Cu")
		(net "M_B_CPU1_SB_DQ<30>")
	)
	(segment
		(start 66.534284 -199.035162)
		(end 66.298318 -198.799196)
		(width 0.18288)
		(layer "In4.Cu")
		(net "M_B_CPU1_SB_DQ<30>")
	)
	(segment
		(start 57.86755 -197.884542)
		(end 57.68467 -198.067422)
		(width 0.18288)
		(layer "In4.Cu")
		(net "M_B_CPU1_SB_DQ<30>")
	)
	(segment
		(start 85.052154 -223.256348)
		(end 85.043264 -223.251268)
		(width 0.088646)
		(layer "In4.Cu")
		(net "M_B_CPU1_SB_DQ<30>")
	)
	(segment
		(start 57.68467 -198.067422)
		(end 57.35955 -198.067422)
		(width 0.18288)
		(layer "In4.Cu")
		(net "M_B_CPU1_SB_DQ<30>")
	)
	(segment
		(start 61.30925 -197.389496)
		(end 60.729876 -197.389496)
		(width 0.18288)
		(layer "In4.Cu")
		(net "M_B_CPU1_SB_DQ<30>")
	)
	(segment
		(start 57.17667 -197.884542)
		(end 57.17667 -197.720204)
		(width 0.18288)
		(layer "In4.Cu")
		(net "M_B_CPU1_SB_DQ<30>")
	)
	(segment
		(start 53.125624 -197.996048)
		(end 53.125624 -198.580756)
		(width 0.18288)
		(layer "In4.Cu")
		(net "M_B_CPU1_SB_DQ<30>")
	)
	(segment
		(start 57.17667 -197.720204)
		(end 56.99379 -197.537324)
		(width 0.18288)
		(layer "In4.Cu")
		(net "M_B_CPU1_SB_DQ<30>")
	)
	(segment
		(start 65.344802 -197.661022)
		(end 64.438022 -197.661022)
		(width 0.18288)
		(layer "In4.Cu")
		(net "M_B_CPU1_SB_DQ<30>")
	)
	(segment
		(start 83.690968 -222.51289)
		(end 82.944462 -221.766384)
		(width 0.088646)
		(layer "In4.Cu")
		(net "M_B_CPU1_SB_DQ<30>")
	)
	(segment
		(start 53.816504 -198.441564)
		(end 53.816504 -197.996048)
		(width 0.18288)
		(layer "In4.Cu")
		(net "M_B_CPU1_SB_DQ<30>")
	)
	(segment
		(start 58.976006 -197.537324)
		(end 58.05043 -197.537324)
		(width 0.18288)
		(layer "In4.Cu")
		(net "M_B_CPU1_SB_DQ<30>")
	)
	(segment
		(start 52.251864 -197.813168)
		(end 51.560984 -197.813168)
		(width 0.18288)
		(layer "In4.Cu")
		(net "M_B_CPU1_SB_DQ<30>")
	)
	(segment
		(start 54.315868 -198.624444)
		(end 53.999384 -198.624444)
		(width 0.18288)
		(layer "In4.Cu")
		(net "M_B_CPU1_SB_DQ<30>")
	)
	(segment
		(start 54.507384 -197.996048)
		(end 54.507384 -198.432928)
		(width 0.18288)
		(layer "In4.Cu")
		(net "M_B_CPU1_SB_DQ<30>")
	)
	(segment
		(start 65.567052 -198.322692)
		(end 65.567052 -197.883272)
		(width 0.18288)
		(layer "In4.Cu")
		(net "M_B_CPU1_SB_DQ<30>")
	)
	(segment
		(start 67.249802 -199.555608)
		(end 67.250056 -199.297544)
		(width 0.18288)
		(layer "In4.Cu")
		(net "M_B_CPU1_SB_DQ<30>")
	)
	(segment
		(start 66.792856 -199.035416)
		(end 66.534284 -199.035162)
		(width 0.18288)
		(layer "In4.Cu")
		(net "M_B_CPU1_SB_DQ<30>")
	)
	(segment
		(start 85.482176 -224.118424)
		(end 85.458046 -224.02927)
		(width 0.088646)
		(layer "In4.Cu")
		(net "M_B_CPU1_SB_DQ<30>")
	)
	(segment
		(start 64.438022 -197.661022)
		(end 64.18707 -197.41007)
		(width 0.18288)
		(layer "In4.Cu")
		(net "M_B_CPU1_SB_DQ<30>")
	)
	(segment
		(start 53.999384 -198.624444)
		(end 53.816504 -198.441564)
		(width 0.18288)
		(layer "In4.Cu")
		(net "M_B_CPU1_SB_DQ<30>")
	)
	(segment
		(start 63.124334 -197.771512)
		(end 61.691266 -197.771512)
		(width 0.18288)
		(layer "In4.Cu")
		(net "M_B_CPU1_SB_DQ<30>")
	)
	(segment
		(start 81.18856 -221.766384)
		(end 77.43952 -218.017344)
		(width 0.18288)
		(layer "In4.Cu")
		(net "M_B_CPU1_SB_DQ<30>")
	)
	(segment
		(start 58.05043 -197.537324)
		(end 57.86755 -197.720204)
		(width 0.18288)
		(layer "In4.Cu")
		(net "M_B_CPU1_SB_DQ<30>")
	)
	(segment
		(start 67.249802 -199.75068)
		(end 67.249802 -199.555608)
		(width 0.18288)
		(layer "In4.Cu")
		(net "M_B_CPU1_SB_DQ<30>")
	)
	(segment
		(start 71.728076 -204.228954)
		(end 67.249802 -199.75068)
		(width 0.18288)
		(layer "In4.Cu")
		(net "M_B_CPU1_SB_DQ<30>")
	)
	(segment
		(start 52.643532 -198.763636)
		(end 52.434744 -198.554848)
		(width 0.18288)
		(layer "In4.Cu")
		(net "M_B_CPU1_SB_DQ<30>")
	)
	(segment
		(start 83.91652 -222.51289)
		(end 83.690968 -222.51289)
		(width 0.088646)
		(layer "In4.Cu")
		(net "M_B_CPU1_SB_DQ<30>")
	)
	(segment
		(start 85.230716 -223.59112)
		(end 85.230716 -223.575626)
		(width 0.088646)
		(layer "In4.Cu")
		(net "M_B_CPU1_SB_DQ<30>")
	)
	(segment
		(start 66.043556 -198.799196)
		(end 65.567052 -198.322692)
		(width 0.18288)
		(layer "In4.Cu")
		(net "M_B_CPU1_SB_DQ<30>")
	)
	(segment
		(start 53.633624 -197.813168)
		(end 53.308504 -197.813168)
		(width 0.18288)
		(layer "In4.Cu")
		(net "M_B_CPU1_SB_DQ<30>")
	)
	(segment
		(start 63.49619 -197.661022)
		(end 63.234824 -197.661022)
		(width 0.18288)
		(layer "In4.Cu")
		(net "M_B_CPU1_SB_DQ<30>")
	)
	(segment
		(start 53.308504 -197.813168)
		(end 53.125624 -197.996048)
		(width 0.18288)
		(layer "In4.Cu")
		(net "M_B_CPU1_SB_DQ<30>")
	)
	(segment
		(start 63.747142 -197.41007)
		(end 63.49619 -197.661022)
		(width 0.18288)
		(layer "In4.Cu")
		(net "M_B_CPU1_SB_DQ<30>")
	)
	(segment
		(start 60.337192 -197.78218)
		(end 59.220862 -197.78218)
		(width 0.18288)
		(layer "In4.Cu")
		(net "M_B_CPU1_SB_DQ<30>")
	)
	(segment
		(start 85.325712 -224.389442)
		(end 85.482176 -224.118424)
		(width 0.088646)
		(layer "In4.Cu")
		(net "M_B_CPU1_SB_DQ<30>")
	)
	(segment
		(start 64.18707 -197.41007)
		(end 63.747142 -197.41007)
		(width 0.18288)
		(layer "In4.Cu")
		(net "M_B_CPU1_SB_DQ<30>")
	)
	(segment
		(start 57.35955 -198.067422)
		(end 57.17667 -197.884542)
		(width 0.18288)
		(layer "In4.Cu")
		(net "M_B_CPU1_SB_DQ<30>")
	)
	(segment
		(start 54.690264 -197.813168)
		(end 54.507384 -197.996048)
		(width 0.18288)
		(layer "In4.Cu")
		(net "M_B_CPU1_SB_DQ<30>")
	)
	(segment
		(start 82.944462 -221.766384)
		(end 82.708496 -221.766384)
		(width 0.088646)
		(layer "In4.Cu")
		(net "M_B_CPU1_SB_DQ<30>")
	)
	(segment
		(start 59.220862 -197.78218)
		(end 58.976006 -197.537324)
		(width 0.18288)
		(layer "In4.Cu")
		(net "M_B_CPU1_SB_DQ<30>")
	)
	(segment
		(start 51.560984 -197.813168)
		(end 51.064414 -197.316598)
		(width 0.18288)
		(layer "In4.Cu")
		(net "M_B_CPU1_SB_DQ<30>")
	)
	(segment
		(start 60.729876 -197.389496)
		(end 60.337192 -197.78218)
		(width 0.18288)
		(layer "In4.Cu")
		(net "M_B_CPU1_SB_DQ<30>")
	)
	(segment
		(start 53.125624 -198.580756)
		(end 52.942744 -198.763636)
		(width 0.18288)
		(layer "In4.Cu")
		(net "M_B_CPU1_SB_DQ<30>")
	)
	(segment
		(start 52.434744 -197.996048)
		(end 52.251864 -197.813168)
		(width 0.18288)
		(layer "In4.Cu")
		(net "M_B_CPU1_SB_DQ<30>")
	)
	(segment
		(start 54.507384 -198.432928)
		(end 54.315868 -198.624444)
		(width 0.18288)
		(layer "In4.Cu")
		(net "M_B_CPU1_SB_DQ<30>")
	)
	(segment
		(start 52.434744 -198.554848)
		(end 52.434744 -197.996048)
		(width 0.18288)
		(layer "In4.Cu")
		(net "M_B_CPU1_SB_DQ<30>")
	)
	(segment
		(start 56.027066 -197.813168)
		(end 54.690264 -197.813168)
		(width 0.18288)
		(layer "In4.Cu")
		(net "M_B_CPU1_SB_DQ<30>")
	)
	(segment
		(start 56.30291 -197.537324)
		(end 56.027066 -197.813168)
		(width 0.18288)
		(layer "In4.Cu")
		(net "M_B_CPU1_SB_DQ<30>")
	)
	(segment
		(start 82.708496 -221.766384)
		(end 81.18856 -221.766384)
		(width 0.18288)
		(layer "In4.Cu")
		(net "M_B_CPU1_SB_DQ<30>")
	)
	(segment
		(start 63.234824 -197.661022)
		(end 63.124334 -197.771512)
		(width 0.18288)
		(layer "In4.Cu")
		(net "M_B_CPU1_SB_DQ<30>")
	)
	(arc
		(start 85.043264 -223.251268)
		(mid 84.839783 -223.050464)
		(end 84.760562 -222.77578)
		(width 0.088646)
		(layer "In4.Cu")
		(net "M_B_CPU1_SB_DQ<30>")
	)
	(arc
		(start 84.57311 -222.437198)
		(mid 84.385912 -222.387055)
		(end 84.198714 -222.437198)
		(width 0.088646)
		(layer "In4.Cu")
		(net "M_B_CPU1_SB_DQ<30>")
	)
	(arc
		(start 85.458046 -224.02927)
		(mid 85.294014 -223.836321)
		(end 85.230716 -223.59112)
		(width 0.088646)
		(layer "In4.Cu")
		(net "M_B_CPU1_SB_DQ<30>")
	)
	(arc
		(start 85.230716 -223.575626)
		(mid 85.183037 -223.392726)
		(end 85.052154 -223.256348)
		(width 0.088646)
		(layer "In4.Cu")
		(net "M_B_CPU1_SB_DQ<30>")
	)
	(arc
		(start 84.760562 -222.761556)
		(mid 84.712883 -222.578656)
		(end 84.582 -222.442278)
		(width 0.088646)
		(layer "In4.Cu")
		(net "M_B_CPU1_SB_DQ<30>")
	)
	(arc
		(start 83.952842 -222.511874)
		(mid 83.934689 -222.512677)
		(end 83.91652 -222.51289)
		(width 0.088646)
		(layer "In4.Cu")
		(net "M_B_CPU1_SB_DQ<30>")
	)
	(arc
		(start 84.198714 -222.437198)
		(mid 84.080083 -222.488718)
		(end 83.952842 -222.511874)
		(width 0.088646)
		(layer "In4.Cu")
		(net "M_B_CPU1_SB_DQ<30>")
	)
	(segment
		(start 45.000418 -230.891842)
		(end 44.745402 -230.891842)
		(width 0.101854)
		(layer "F.Cu")
		(net "M_B_CPU1_SB_DQ<2>")
	)
	(segment
		(start 44.745402 -230.891842)
		(end 44.735242 -230.881682)
		(width 0.101854)
		(layer "F.Cu")
		(net "M_B_CPU1_SB_DQ<2>")
	)
	(segment
		(start 47.83709 -231.035606)
		(end 47.693326 -230.891842)
		(width 0.20066)
		(layer "F.Cu")
		(net "M_B_CPU1_SB_DQ<2>")
	)
	(segment
		(start 49.959514 -231.316784)
		(end 48.64481 -231.316784)
		(width 0.20066)
		(layer "F.Cu")
		(net "M_B_CPU1_SB_DQ<2>")
	)
	(segment
		(start 43.562778 -231.316784)
		(end 42.415714 -231.316784)
		(width 0.20066)
		(layer "F.Cu")
		(net "M_B_CPU1_SB_DQ<2>")
	)
	(segment
		(start 47.060358 -230.891842)
		(end 45.000418 -230.891842)
		(width 0.1016)
		(layer "F.Cu")
		(net "M_B_CPU1_SB_DQ<2>")
	)
	(segment
		(start 47.83709 -231.361234)
		(end 47.83709 -231.035606)
		(width 0.20066)
		(layer "F.Cu")
		(net "M_B_CPU1_SB_DQ<2>")
	)
	(segment
		(start 44.735242 -230.881682)
		(end 43.99788 -230.881682)
		(width 0.20066)
		(layer "F.Cu")
		(net "M_B_CPU1_SB_DQ<2>")
	)
	(segment
		(start 51.064414 -231.316784)
		(end 49.959514 -231.316784)
		(width 0.20066)
		(layer "F.Cu")
		(net "M_B_CPU1_SB_DQ<2>")
	)
	(segment
		(start 93.314012 -237.133638)
		(end 93.314012 -236.597952)
		(width 0.20066)
		(layer "F.Cu")
		(net "M_B_CPU1_SB_DQ<2>")
	)
	(segment
		(start 48.64481 -231.316784)
		(end 48.432974 -231.52862)
		(width 0.20066)
		(layer "F.Cu")
		(net "M_B_CPU1_SB_DQ<2>")
	)
	(segment
		(start 48.004476 -231.52862)
		(end 47.83709 -231.361234)
		(width 0.20066)
		(layer "F.Cu")
		(net "M_B_CPU1_SB_DQ<2>")
	)
	(segment
		(start 43.99788 -230.881682)
		(end 43.562778 -231.316784)
		(width 0.20066)
		(layer "F.Cu")
		(net "M_B_CPU1_SB_DQ<2>")
	)
	(segment
		(start 48.432974 -231.52862)
		(end 48.004476 -231.52862)
		(width 0.20066)
		(layer "F.Cu")
		(net "M_B_CPU1_SB_DQ<2>")
	)
	(segment
		(start 47.693326 -230.891842)
		(end 47.060358 -230.891842)
		(width 0.20066)
		(layer "F.Cu")
		(net "M_B_CPU1_SB_DQ<2>")
	)
	(segment
		(start 93.314266 -237.133892)
		(end 93.314012 -237.133638)
		(width 0.20066)
		(layer "F.Cu")
		(net "M_B_CPU1_SB_DQ<2>")
	)
	(segment
		(start 86.078568 -237.08741)
		(end 86.068154 -237.093506)
		(width 0.088646)
		(layer "In4.Cu")
		(net "M_B_CPU1_SB_DQ<2>")
	)
	(segment
		(start 70.8025 -235.827316)
		(end 70.54088 -235.565696)
		(width 0.18288)
		(layer "In4.Cu")
		(net "M_B_CPU1_SB_DQ<2>")
	)
	(segment
		(start 54.888892 -230.875332)
		(end 54.244748 -230.875332)
		(width 0.18288)
		(layer "In4.Cu")
		(net "M_B_CPU1_SB_DQ<2>")
	)
	(segment
		(start 83.643724 -237.85068)
		(end 83.324954 -237.53191)
		(width 0.088646)
		(layer "In4.Cu")
		(net "M_B_CPU1_SB_DQ<2>")
	)
	(segment
		(start 60.443872 -230.737918)
		(end 59.078876 -230.737918)
		(width 0.18288)
		(layer "In4.Cu")
		(net "M_B_CPU1_SB_DQ<2>")
	)
	(segment
		(start 66.438526 -233.212386)
		(end 66.438526 -232.80624)
		(width 0.18288)
		(layer "In4.Cu")
		(net "M_B_CPU1_SB_DQ<2>")
	)
	(segment
		(start 69.563488 -234.134152)
		(end 69.301868 -233.872532)
		(width 0.18288)
		(layer "In4.Cu")
		(net "M_B_CPU1_SB_DQ<2>")
	)
	(segment
		(start 87.018114 -237.08741)
		(end 87.0077 -237.093506)
		(width 0.088646)
		(layer "In4.Cu")
		(net "M_B_CPU1_SB_DQ<2>")
	)
	(segment
		(start 68.847716 -233.872532)
		(end 68.586096 -233.610912)
		(width 0.18288)
		(layer "In4.Cu")
		(net "M_B_CPU1_SB_DQ<2>")
	)
	(segment
		(start 53.188108 -230.875332)
		(end 52.018438 -230.875332)
		(width 0.18288)
		(layer "In4.Cu")
		(net "M_B_CPU1_SB_DQ<2>")
	)
	(segment
		(start 70.54088 -235.565696)
		(end 70.54088 -235.111544)
		(width 0.18288)
		(layer "In4.Cu")
		(net "M_B_CPU1_SB_DQ<2>")
	)
	(segment
		(start 85.138514 -237.08741)
		(end 85.129624 -237.09249)
		(width 0.088646)
		(layer "In4.Cu")
		(net "M_B_CPU1_SB_DQ<2>")
	)
	(segment
		(start 57.697878 -230.65613)
		(end 57.31637 -231.037638)
		(width 0.18288)
		(layer "In4.Cu")
		(net "M_B_CPU1_SB_DQ<2>")
	)
	(segment
		(start 55.631588 -231.618028)
		(end 54.888892 -230.875332)
		(width 0.18288)
		(layer "In4.Cu")
		(net "M_B_CPU1_SB_DQ<2>")
	)
	(segment
		(start 57.31637 -231.436672)
		(end 57.135014 -231.618028)
		(width 0.18288)
		(layer "In4.Cu")
		(net "M_B_CPU1_SB_DQ<2>")
	)
	(segment
		(start 69.301868 -233.872532)
		(end 68.847716 -233.872532)
		(width 0.18288)
		(layer "In4.Cu")
		(net "M_B_CPU1_SB_DQ<2>")
	)
	(segment
		(start 57.135014 -231.618028)
		(end 55.631588 -231.618028)
		(width 0.18288)
		(layer "In4.Cu")
		(net "M_B_CPU1_SB_DQ<2>")
	)
	(segment
		(start 51.576986 -231.316784)
		(end 51.064414 -231.316784)
		(width 0.18288)
		(layer "In4.Cu")
		(net "M_B_CPU1_SB_DQ<2>")
	)
	(segment
		(start 54.061868 -231.256078)
		(end 53.878988 -231.438958)
		(width 0.18288)
		(layer "In4.Cu")
		(net "M_B_CPU1_SB_DQ<2>")
	)
	(segment
		(start 58.242962 -231.439466)
		(end 58.242962 -230.809292)
		(width 0.18288)
		(layer "In4.Cu")
		(net "M_B_CPU1_SB_DQ<2>")
	)
	(segment
		(start 57.31637 -231.037638)
		(end 57.31637 -231.436672)
		(width 0.18288)
		(layer "In4.Cu")
		(net "M_B_CPU1_SB_DQ<2>")
	)
	(segment
		(start 54.061868 -231.058212)
		(end 54.061868 -231.256078)
		(width 0.18288)
		(layer "In4.Cu")
		(net "M_B_CPU1_SB_DQ<2>")
	)
	(segment
		(start 84.951062 -237.411768)
		(end 84.951062 -237.427262)
		(width 0.088646)
		(layer "In4.Cu")
		(net "M_B_CPU1_SB_DQ<2>")
	)
	(segment
		(start 89.287096 -237.096046)
		(end 89.272364 -237.08741)
		(width 0.088646)
		(layer "In4.Cu")
		(net "M_B_CPU1_SB_DQ<2>")
	)
	(segment
		(start 59.078876 -230.737918)
		(end 58.949082 -230.867712)
		(width 0.18288)
		(layer "In4.Cu")
		(net "M_B_CPU1_SB_DQ<2>")
	)
	(segment
		(start 70.27926 -234.849924)
		(end 69.825108 -234.849924)
		(width 0.18288)
		(layer "In4.Cu")
		(net "M_B_CPU1_SB_DQ<2>")
	)
	(segment
		(start 58.441082 -231.637586)
		(end 58.242962 -231.439466)
		(width 0.18288)
		(layer "In4.Cu")
		(net "M_B_CPU1_SB_DQ<2>")
	)
	(segment
		(start 52.018438 -230.875332)
		(end 51.576986 -231.316784)
		(width 0.18288)
		(layer "In4.Cu")
		(net "M_B_CPU1_SB_DQ<2>")
	)
	(segment
		(start 67.129406 -233.223054)
		(end 66.946526 -233.405934)
		(width 0.18288)
		(layer "In4.Cu")
		(net "M_B_CPU1_SB_DQ<2>")
	)
	(segment
		(start 60.784232 -231.078278)
		(end 60.443872 -230.737918)
		(width 0.18288)
		(layer "In4.Cu")
		(net "M_B_CPU1_SB_DQ<2>")
	)
	(segment
		(start 91.151964 -237.087156)
		(end 91.151964 -237.08741)
		(width 0.088646)
		(layer "In4.Cu")
		(net "M_B_CPU1_SB_DQ<2>")
	)
	(segment
		(start 83.916266 -237.85068)
		(end 83.643724 -237.85068)
		(width 0.088646)
		(layer "In4.Cu")
		(net "M_B_CPU1_SB_DQ<2>")
	)
	(segment
		(start 72.961246 -237.53191)
		(end 72.234044 -236.804708)
		(width 0.18288)
		(layer "In4.Cu")
		(net "M_B_CPU1_SB_DQ<2>")
	)
	(segment
		(start 68.586096 -233.15676)
		(end 68.052696 -232.62336)
		(width 0.18288)
		(layer "In4.Cu")
		(net "M_B_CPU1_SB_DQ<2>")
	)
	(segment
		(start 83.324954 -237.53191)
		(end 83.064096 -237.53191)
		(width 0.088646)
		(layer "In4.Cu")
		(net "M_B_CPU1_SB_DQ<2>")
	)
	(segment
		(start 64.040258 -231.557322)
		(end 63.781178 -231.557322)
		(width 0.18288)
		(layer "In4.Cu")
		(net "M_B_CPU1_SB_DQ<2>")
	)
	(segment
		(start 87.958168 -237.08741)
		(end 87.947754 -237.093506)
		(width 0.088646)
		(layer "In4.Cu")
		(net "M_B_CPU1_SB_DQ<2>")
	)
	(segment
		(start 68.586096 -233.610912)
		(end 68.586096 -233.15676)
		(width 0.18288)
		(layer "In4.Cu")
		(net "M_B_CPU1_SB_DQ<2>")
	)
	(segment
		(start 69.825108 -234.849924)
		(end 69.563488 -234.588304)
		(width 0.18288)
		(layer "In4.Cu")
		(net "M_B_CPU1_SB_DQ<2>")
	)
	(segment
		(start 90.226896 -237.096046)
		(end 90.212164 -237.08741)
		(width 0.088646)
		(layer "In4.Cu")
		(net "M_B_CPU1_SB_DQ<2>")
	)
	(segment
		(start 66.632074 -233.405934)
		(end 66.438526 -233.212386)
		(width 0.18288)
		(layer "In4.Cu")
		(net "M_B_CPU1_SB_DQ<2>")
	)
	(segment
		(start 60.784232 -231.414574)
		(end 60.784232 -231.078278)
		(width 0.18288)
		(layer "In4.Cu")
		(net "M_B_CPU1_SB_DQ<2>")
	)
	(segment
		(start 68.052696 -232.62336)
		(end 67.312286 -232.62336)
		(width 0.18288)
		(layer "In4.Cu")
		(net "M_B_CPU1_SB_DQ<2>")
	)
	(segment
		(start 83.064096 -237.53191)
		(end 72.961246 -237.53191)
		(width 0.18288)
		(layer "In4.Cu")
		(net "M_B_CPU1_SB_DQ<2>")
	)
	(segment
		(start 61.025024 -231.655366)
		(end 60.784232 -231.414574)
		(width 0.18288)
		(layer "In4.Cu")
		(net "M_B_CPU1_SB_DQ<2>")
	)
	(segment
		(start 58.0898 -230.65613)
		(end 57.697878 -230.65613)
		(width 0.18288)
		(layer "In4.Cu")
		(net "M_B_CPU1_SB_DQ<2>")
	)
	(segment
		(start 66.946526 -233.405934)
		(end 66.632074 -233.405934)
		(width 0.18288)
		(layer "In4.Cu")
		(net "M_B_CPU1_SB_DQ<2>")
	)
	(segment
		(start 91.717114 -237.087156)
		(end 91.711272 -237.090712)
		(width 0.088646)
		(layer "In4.Cu")
		(net "M_B_CPU1_SB_DQ<2>")
	)
	(segment
		(start 63.598806 -231.739694)
		(end 61.97092 -231.739694)
		(width 0.18288)
		(layer "In4.Cu")
		(net "M_B_CPU1_SB_DQ<2>")
	)
	(segment
		(start 72.234044 -236.804708)
		(end 71.779892 -236.804708)
		(width 0.18288)
		(layer "In4.Cu")
		(net "M_B_CPU1_SB_DQ<2>")
	)
	(segment
		(start 61.858144 -231.692958)
		(end 61.767466 -231.655366)
		(width 0.18288)
		(layer "In4.Cu")
		(net "M_B_CPU1_SB_DQ<2>")
	)
	(segment
		(start 71.256652 -235.827316)
		(end 70.8025 -235.827316)
		(width 0.18288)
		(layer "In4.Cu")
		(net "M_B_CPU1_SB_DQ<2>")
	)
	(segment
		(start 53.370988 -231.058212)
		(end 53.188108 -230.875332)
		(width 0.18288)
		(layer "In4.Cu")
		(net "M_B_CPU1_SB_DQ<2>")
	)
	(segment
		(start 58.789062 -231.637586)
		(end 58.441082 -231.637586)
		(width 0.18288)
		(layer "In4.Cu")
		(net "M_B_CPU1_SB_DQ<2>")
	)
	(segment
		(start 71.518272 -236.543088)
		(end 71.518272 -236.088936)
		(width 0.18288)
		(layer "In4.Cu")
		(net "M_B_CPU1_SB_DQ<2>")
	)
	(segment
		(start 53.878988 -231.438958)
		(end 53.553868 -231.438958)
		(width 0.18288)
		(layer "In4.Cu")
		(net "M_B_CPU1_SB_DQ<2>")
	)
	(segment
		(start 71.779892 -236.804708)
		(end 71.518272 -236.543088)
		(width 0.18288)
		(layer "In4.Cu")
		(net "M_B_CPU1_SB_DQ<2>")
	)
	(segment
		(start 91.722956 -237.083854)
		(end 91.717114 -237.087156)
		(width 0.088646)
		(layer "In4.Cu")
		(net "M_B_CPU1_SB_DQ<2>")
	)
	(segment
		(start 67.312286 -232.62336)
		(end 67.129406 -232.80624)
		(width 0.18288)
		(layer "In4.Cu")
		(net "M_B_CPU1_SB_DQ<2>")
	)
	(segment
		(start 71.518272 -236.088936)
		(end 71.256652 -235.827316)
		(width 0.18288)
		(layer "In4.Cu")
		(net "M_B_CPU1_SB_DQ<2>")
	)
	(segment
		(start 66.438526 -232.80624)
		(end 66.255646 -232.62336)
		(width 0.18288)
		(layer "In4.Cu")
		(net "M_B_CPU1_SB_DQ<2>")
	)
	(segment
		(start 67.129406 -232.80624)
		(end 67.129406 -233.223054)
		(width 0.18288)
		(layer "In4.Cu")
		(net "M_B_CPU1_SB_DQ<2>")
	)
	(segment
		(start 69.563488 -234.588304)
		(end 69.563488 -234.134152)
		(width 0.18288)
		(layer "In4.Cu")
		(net "M_B_CPU1_SB_DQ<2>")
	)
	(segment
		(start 54.244748 -230.875332)
		(end 54.061868 -231.058212)
		(width 0.18288)
		(layer "In4.Cu")
		(net "M_B_CPU1_SB_DQ<2>")
	)
	(segment
		(start 61.767466 -231.655366)
		(end 61.025024 -231.655366)
		(width 0.18288)
		(layer "In4.Cu")
		(net "M_B_CPU1_SB_DQ<2>")
	)
	(segment
		(start 58.949082 -231.477566)
		(end 58.789062 -231.637586)
		(width 0.18288)
		(layer "In4.Cu")
		(net "M_B_CPU1_SB_DQ<2>")
	)
	(segment
		(start 61.97092 -231.739694)
		(end 61.858144 -231.692958)
		(width 0.18288)
		(layer "In4.Cu")
		(net "M_B_CPU1_SB_DQ<2>")
	)
	(segment
		(start 66.255646 -232.62336)
		(end 65.106296 -232.62336)
		(width 0.18288)
		(layer "In4.Cu")
		(net "M_B_CPU1_SB_DQ<2>")
	)
	(segment
		(start 53.370988 -231.256078)
		(end 53.370988 -231.058212)
		(width 0.18288)
		(layer "In4.Cu")
		(net "M_B_CPU1_SB_DQ<2>")
	)
	(segment
		(start 63.781178 -231.557322)
		(end 63.598806 -231.739694)
		(width 0.18288)
		(layer "In4.Cu")
		(net "M_B_CPU1_SB_DQ<2>")
	)
	(segment
		(start 70.54088 -235.111544)
		(end 70.27926 -234.849924)
		(width 0.18288)
		(layer "In4.Cu")
		(net "M_B_CPU1_SB_DQ<2>")
	)
	(segment
		(start 93.314012 -236.597952)
		(end 92.548456 -237.017306)
		(width 0.088646)
		(layer "In4.Cu")
		(net "M_B_CPU1_SB_DQ<2>")
	)
	(segment
		(start 58.949082 -230.867712)
		(end 58.949082 -231.477566)
		(width 0.18288)
		(layer "In4.Cu")
		(net "M_B_CPU1_SB_DQ<2>")
	)
	(segment
		(start 65.106296 -232.62336)
		(end 64.040258 -231.557322)
		(width 0.18288)
		(layer "In4.Cu")
		(net "M_B_CPU1_SB_DQ<2>")
	)
	(segment
		(start 58.242962 -230.809292)
		(end 58.0898 -230.65613)
		(width 0.18288)
		(layer "In4.Cu")
		(net "M_B_CPU1_SB_DQ<2>")
	)
	(segment
		(start 53.553868 -231.438958)
		(end 53.370988 -231.256078)
		(width 0.18288)
		(layer "In4.Cu")
		(net "M_B_CPU1_SB_DQ<2>")
	)
	(segment
		(start 84.118196 -237.909862)
		(end 84.103464 -237.901226)
		(width 0.088646)
		(layer "In4.Cu")
		(net "M_B_CPU1_SB_DQ<2>")
	)
	(arc
		(start 84.103464 -237.901226)
		(mid 84.013192 -237.863627)
		(end 83.916266 -237.85068)
		(width 0.088646)
		(layer "In4.Cu")
		(net "M_B_CPU1_SB_DQ<2>")
	)
	(arc
		(start 90.212164 -237.08741)
		(mid 90.024966 -237.037233)
		(end 89.837768 -237.08741)
		(width 0.088646)
		(layer "In4.Cu")
		(net "M_B_CPU1_SB_DQ<2>")
	)
	(arc
		(start 87.947754 -237.093506)
		(mid 87.669322 -237.163352)
		(end 87.39251 -237.08741)
		(width 0.088646)
		(layer "In4.Cu")
		(net "M_B_CPU1_SB_DQ<2>")
	)
	(arc
		(start 91.151964 -237.08741)
		(mid 90.964766 -237.037233)
		(end 90.777568 -237.08741)
		(width 0.088646)
		(layer "In4.Cu")
		(net "M_B_CPU1_SB_DQ<2>")
	)
	(arc
		(start 90.777568 -237.08741)
		(mid 90.503369 -237.163245)
		(end 90.226896 -237.096046)
		(width 0.088646)
		(layer "In4.Cu")
		(net "M_B_CPU1_SB_DQ<2>")
	)
	(arc
		(start 85.51291 -237.08741)
		(mid 85.325712 -237.037267)
		(end 85.138514 -237.08741)
		(width 0.088646)
		(layer "In4.Cu")
		(net "M_B_CPU1_SB_DQ<2>")
	)
	(arc
		(start 89.837768 -237.08741)
		(mid 89.563569 -237.163245)
		(end 89.287096 -237.096046)
		(width 0.088646)
		(layer "In4.Cu")
		(net "M_B_CPU1_SB_DQ<2>")
	)
	(arc
		(start 91.982036 -237.044992)
		(mid 91.848989 -237.04104)
		(end 91.722956 -237.083854)
		(width 0.088646)
		(layer "In4.Cu")
		(net "M_B_CPU1_SB_DQ<2>")
	)
	(arc
		(start 87.0077 -237.093506)
		(mid 86.729522 -237.163229)
		(end 86.452964 -237.08741)
		(width 0.088646)
		(layer "In4.Cu")
		(net "M_B_CPU1_SB_DQ<2>")
	)
	(arc
		(start 86.068154 -237.093506)
		(mid 85.789722 -237.163352)
		(end 85.51291 -237.08741)
		(width 0.088646)
		(layer "In4.Cu")
		(net "M_B_CPU1_SB_DQ<2>")
	)
	(arc
		(start 87.39251 -237.08741)
		(mid 87.205312 -237.037267)
		(end 87.018114 -237.08741)
		(width 0.088646)
		(layer "In4.Cu")
		(net "M_B_CPU1_SB_DQ<2>")
	)
	(arc
		(start 91.711272 -237.090712)
		(mid 91.431137 -237.163028)
		(end 91.151964 -237.087156)
		(width 0.088646)
		(layer "In4.Cu")
		(net "M_B_CPU1_SB_DQ<2>")
	)
	(arc
		(start 88.897968 -237.08741)
		(mid 88.615266 -237.163186)
		(end 88.332564 -237.08741)
		(width 0.088646)
		(layer "In4.Cu")
		(net "M_B_CPU1_SB_DQ<2>")
	)
	(arc
		(start 92.46489 -237.04804)
		(mid 92.22331 -237.071003)
		(end 91.982036 -237.044992)
		(width 0.088646)
		(layer "In4.Cu")
		(net "M_B_CPU1_SB_DQ<2>")
	)
	(arc
		(start 89.272364 -237.08741)
		(mid 89.085166 -237.037233)
		(end 88.897968 -237.08741)
		(width 0.088646)
		(layer "In4.Cu")
		(net "M_B_CPU1_SB_DQ<2>")
	)
	(arc
		(start 85.129624 -237.09249)
		(mid 84.99871 -237.22885)
		(end 84.951062 -237.411768)
		(width 0.088646)
		(layer "In4.Cu")
		(net "M_B_CPU1_SB_DQ<2>")
	)
	(arc
		(start 86.452964 -237.08741)
		(mid 86.265766 -237.037267)
		(end 86.078568 -237.08741)
		(width 0.088646)
		(layer "In4.Cu")
		(net "M_B_CPU1_SB_DQ<2>")
	)
	(arc
		(start 84.951062 -237.427262)
		(mid 84.871692 -237.700996)
		(end 84.668868 -237.901226)
		(width 0.088646)
		(layer "In4.Cu")
		(net "M_B_CPU1_SB_DQ<2>")
	)
	(arc
		(start 88.332564 -237.08741)
		(mid 88.145366 -237.037233)
		(end 87.958168 -237.08741)
		(width 0.088646)
		(layer "In4.Cu")
		(net "M_B_CPU1_SB_DQ<2>")
	)
	(arc
		(start 84.668868 -237.901226)
		(mid 84.394669 -237.977061)
		(end 84.118196 -237.909862)
		(width 0.088646)
		(layer "In4.Cu")
		(net "M_B_CPU1_SB_DQ<2>")
	)
	(arc
		(start 92.548456 -237.017306)
		(mid 92.507844 -237.035854)
		(end 92.46489 -237.04804)
		(width 0.088646)
		(layer "In4.Cu")
		(net "M_B_CPU1_SB_DQ<2>")
	)
	(segment
		(start 40.520112 -196.52361)
		(end 40.36568 -196.678042)
		(width 0.20066)
		(layer "F.Cu")
		(net "M_B_CPU1_SB_DQ<29>")
	)
	(segment
		(start 43.795188 -196.041772)
		(end 43.616626 -196.041772)
		(width 0.20066)
		(layer "F.Cu")
		(net "M_B_CPU1_SB_DQ<29>")
	)
	(segment
		(start 45.859446 -196.466714)
		(end 44.22013 -196.466714)
		(width 0.20066)
		(layer "F.Cu")
		(net "M_B_CPU1_SB_DQ<29>")
	)
	(segment
		(start 46.964346 -196.466714)
		(end 45.859446 -196.466714)
		(width 0.20066)
		(layer "F.Cu")
		(net "M_B_CPU1_SB_DQ<29>")
	)
	(segment
		(start 40.36568 -196.678042)
		(end 39.861236 -196.678042)
		(width 0.20066)
		(layer "F.Cu")
		(net "M_B_CPU1_SB_DQ<29>")
	)
	(segment
		(start 86.735666 -224.111566)
		(end 86.735666 -223.575626)
		(width 0.20066)
		(layer "F.Cu")
		(net "M_B_CPU1_SB_DQ<29>")
	)
	(segment
		(start 43.616626 -196.041772)
		(end 43.285918 -196.041772)
		(width 0.101854)
		(layer "F.Cu")
		(net "M_B_CPU1_SB_DQ<29>")
	)
	(segment
		(start 41.29151 -196.032882)
		(end 40.682672 -196.032882)
		(width 0.20066)
		(layer "F.Cu")
		(net "M_B_CPU1_SB_DQ<29>")
	)
	(segment
		(start 41.3004 -196.041772)
		(end 41.29151 -196.032882)
		(width 0.1016)
		(layer "F.Cu")
		(net "M_B_CPU1_SB_DQ<29>")
	)
	(segment
		(start 40.520112 -196.195442)
		(end 40.520112 -196.52361)
		(width 0.20066)
		(layer "F.Cu")
		(net "M_B_CPU1_SB_DQ<29>")
	)
	(segment
		(start 43.285918 -196.041772)
		(end 41.3004 -196.041772)
		(width 0.1016)
		(layer "F.Cu")
		(net "M_B_CPU1_SB_DQ<29>")
	)
	(segment
		(start 44.22013 -196.466714)
		(end 43.795188 -196.041772)
		(width 0.20066)
		(layer "F.Cu")
		(net "M_B_CPU1_SB_DQ<29>")
	)
	(segment
		(start 40.682672 -196.032882)
		(end 40.520112 -196.195442)
		(width 0.20066)
		(layer "F.Cu")
		(net "M_B_CPU1_SB_DQ<29>")
	)
	(segment
		(start 39.861236 -196.678042)
		(end 39.649908 -196.466714)
		(width 0.20066)
		(layer "F.Cu")
		(net "M_B_CPU1_SB_DQ<29>")
	)
	(segment
		(start 39.649908 -196.466714)
		(end 38.315646 -196.466714)
		(width 0.20066)
		(layer "F.Cu")
		(net "M_B_CPU1_SB_DQ<29>")
	)
	(segment
		(start 78.577948 -216.860882)
		(end 72.966834 -203.314808)
		(width 0.18288)
		(layer "In4.Cu")
		(net "M_B_CPU1_SB_DQ<29>")
	)
	(segment
		(start 50.889662 -195.194936)
		(end 50.885852 -195.191126)
		(width 0.18288)
		(layer "In4.Cu")
		(net "M_B_CPU1_SB_DQ<29>")
	)
	(segment
		(start 85.614764 -222.275654)
		(end 85.608668 -222.272098)
		(width 0.088646)
		(layer "In4.Cu")
		(net "M_B_CPU1_SB_DQ<29>")
	)
	(segment
		(start 86.361016 -223.575626)
		(end 86.361016 -223.557084)
		(width 0.088646)
		(layer "In4.Cu")
		(net "M_B_CPU1_SB_DQ<29>")
	)
	(segment
		(start 82.708496 -220.272864)
		(end 81.98993 -220.272864)
		(width 0.18288)
		(layer "In4.Cu")
		(net "M_B_CPU1_SB_DQ<29>")
	)
	(segment
		(start 81.98993 -220.272864)
		(end 78.577948 -216.860882)
		(width 0.18288)
		(layer "In4.Cu")
		(net "M_B_CPU1_SB_DQ<29>")
	)
	(segment
		(start 51.083464 -195.194936)
		(end 50.889662 -195.194936)
		(width 0.18288)
		(layer "In4.Cu")
		(net "M_B_CPU1_SB_DQ<29>")
	)
	(segment
		(start 86.735666 -223.575626)
		(end 86.89213 -223.846644)
		(width 0.088646)
		(layer "In4.Cu")
		(net "M_B_CPU1_SB_DQ<29>")
	)
	(segment
		(start 72.966834 -203.314808)
		(end 68.942204 -199.290178)
		(width 0.18288)
		(layer "In4.Cu")
		(net "M_B_CPU1_SB_DQ<29>")
	)
	(segment
		(start 68.942204 -199.290178)
		(end 67.816984 -196.57314)
		(width 0.18288)
		(layer "In4.Cu")
		(net "M_B_CPU1_SB_DQ<29>")
	)
	(segment
		(start 50.043588 -195.191126)
		(end 46.964346 -196.466714)
		(width 0.18288)
		(layer "In4.Cu")
		(net "M_B_CPU1_SB_DQ<29>")
	)
	(segment
		(start 85.608668 -222.272098)
		(end 85.599778 -222.267018)
		(width 0.088646)
		(layer "In4.Cu")
		(net "M_B_CPU1_SB_DQ<29>")
	)
	(segment
		(start 50.885852 -195.191126)
		(end 50.043588 -195.191126)
		(width 0.18288)
		(layer "In4.Cu")
		(net "M_B_CPU1_SB_DQ<29>")
	)
	(segment
		(start 85.421216 -221.94774)
		(end 85.421216 -221.937834)
		(width 0.088646)
		(layer "In4.Cu")
		(net "M_B_CPU1_SB_DQ<29>")
	)
	(segment
		(start 86.078568 -223.085914)
		(end 86.069678 -223.080834)
		(width 0.088646)
		(layer "In4.Cu")
		(net "M_B_CPU1_SB_DQ<29>")
	)
	(segment
		(start 84.12099 -221.3991)
		(end 82.994754 -220.272864)
		(width 0.088646)
		(layer "In4.Cu")
		(net "M_B_CPU1_SB_DQ<29>")
	)
	(segment
		(start 67.816984 -196.57314)
		(end 66.435732 -195.191888)
		(width 0.18288)
		(layer "In4.Cu")
		(net "M_B_CPU1_SB_DQ<29>")
	)
	(segment
		(start 66.435732 -195.191888)
		(end 51.086512 -195.191888)
		(width 0.18288)
		(layer "In4.Cu")
		(net "M_B_CPU1_SB_DQ<29>")
	)
	(segment
		(start 51.086512 -195.191888)
		(end 51.083464 -195.194936)
		(width 0.18288)
		(layer "In4.Cu")
		(net "M_B_CPU1_SB_DQ<29>")
	)
	(segment
		(start 86.548468 -223.899984)
		(end 86.539578 -223.894904)
		(width 0.088646)
		(layer "In4.Cu")
		(net "M_B_CPU1_SB_DQ<29>")
	)
	(segment
		(start 82.994754 -220.272864)
		(end 82.708496 -220.272864)
		(width 0.088646)
		(layer "In4.Cu")
		(net "M_B_CPU1_SB_DQ<29>")
	)
	(segment
		(start 86.89213 -223.846644)
		(end 86.871048 -223.924622)
		(width 0.088646)
		(layer "In4.Cu")
		(net "M_B_CPU1_SB_DQ<29>")
	)
	(arc
		(start 84.573364 -221.458282)
		(mid 84.386166 -221.508425)
		(end 84.198968 -221.458282)
		(width 0.088646)
		(layer "In4.Cu")
		(net "M_B_CPU1_SB_DQ<29>")
	)
	(arc
		(start 85.138768 -221.458282)
		(mid 84.856066 -221.382506)
		(end 84.573364 -221.458282)
		(width 0.088646)
		(layer "In4.Cu")
		(net "M_B_CPU1_SB_DQ<29>")
	)
	(arc
		(start 86.069678 -223.080834)
		(mid 85.938764 -222.944474)
		(end 85.891116 -222.761556)
		(width 0.088646)
		(layer "In4.Cu")
		(net "M_B_CPU1_SB_DQ<29>")
	)
	(arc
		(start 85.421216 -221.937834)
		(mid 85.343105 -221.660885)
		(end 85.138768 -221.458282)
		(width 0.088646)
		(layer "In4.Cu")
		(net "M_B_CPU1_SB_DQ<29>")
	)
	(arc
		(start 86.361016 -223.557084)
		(mid 86.280854 -223.284895)
		(end 86.078568 -223.085914)
		(width 0.088646)
		(layer "In4.Cu")
		(net "M_B_CPU1_SB_DQ<29>")
	)
	(arc
		(start 86.871048 -223.924622)
		(mid 86.706952 -223.948969)
		(end 86.548468 -223.899984)
		(width 0.088646)
		(layer "In4.Cu")
		(net "M_B_CPU1_SB_DQ<29>")
	)
	(arc
		(start 85.891116 -222.761556)
		(mid 85.8172 -222.482054)
		(end 85.614764 -222.275654)
		(width 0.088646)
		(layer "In4.Cu")
		(net "M_B_CPU1_SB_DQ<29>")
	)
	(arc
		(start 84.198968 -221.458282)
		(mid 84.158038 -221.431249)
		(end 84.12099 -221.3991)
		(width 0.088646)
		(layer "In4.Cu")
		(net "M_B_CPU1_SB_DQ<29>")
	)
	(arc
		(start 86.539578 -223.894904)
		(mid 86.408664 -223.758544)
		(end 86.361016 -223.575626)
		(width 0.088646)
		(layer "In4.Cu")
		(net "M_B_CPU1_SB_DQ<29>")
	)
	(arc
		(start 85.599778 -222.267018)
		(mid 85.468864 -222.130658)
		(end 85.421216 -221.94774)
		(width 0.088646)
		(layer "In4.Cu")
		(net "M_B_CPU1_SB_DQ<29>")
	)
	(segment
		(start 39.649908 -198.166736)
		(end 38.315646 -198.166736)
		(width 0.20066)
		(layer "F.Cu")
		(net "M_B_CPU1_SB_DQ<28>")
	)
	(segment
		(start 40.520112 -197.943216)
		(end 40.520112 -198.232776)
		(width 0.20066)
		(layer "F.Cu")
		(net "M_B_CPU1_SB_DQ<28>")
	)
	(segment
		(start 40.520112 -198.232776)
		(end 40.347392 -198.405496)
		(width 0.20066)
		(layer "F.Cu")
		(net "M_B_CPU1_SB_DQ<28>")
	)
	(segment
		(start 40.729662 -197.733666)
		(end 40.520112 -197.943216)
		(width 0.20066)
		(layer "F.Cu")
		(net "M_B_CPU1_SB_DQ<28>")
	)
	(segment
		(start 46.964346 -198.166736)
		(end 45.859446 -198.166736)
		(width 0.20066)
		(layer "F.Cu")
		(net "M_B_CPU1_SB_DQ<28>")
	)
	(segment
		(start 85.795866 -224.111566)
		(end 85.795866 -223.575626)
		(width 0.20066)
		(layer "F.Cu")
		(net "M_B_CPU1_SB_DQ<28>")
	)
	(segment
		(start 41.299638 -197.741794)
		(end 41.29151 -197.733666)
		(width 0.101854)
		(layer "F.Cu")
		(net "M_B_CPU1_SB_DQ<28>")
	)
	(segment
		(start 41.547542 -197.741794)
		(end 41.299638 -197.741794)
		(width 0.101854)
		(layer "F.Cu")
		(net "M_B_CPU1_SB_DQ<28>")
	)
	(segment
		(start 43.616626 -197.741794)
		(end 41.547542 -197.741794)
		(width 0.1016)
		(layer "F.Cu")
		(net "M_B_CPU1_SB_DQ<28>")
	)
	(segment
		(start 39.888668 -198.405496)
		(end 39.649908 -198.166736)
		(width 0.20066)
		(layer "F.Cu")
		(net "M_B_CPU1_SB_DQ<28>")
	)
	(segment
		(start 44.490386 -198.166736)
		(end 44.065444 -197.741794)
		(width 0.20066)
		(layer "F.Cu")
		(net "M_B_CPU1_SB_DQ<28>")
	)
	(segment
		(start 41.29151 -197.733666)
		(end 40.729662 -197.733666)
		(width 0.20066)
		(layer "F.Cu")
		(net "M_B_CPU1_SB_DQ<28>")
	)
	(segment
		(start 44.065444 -197.741794)
		(end 43.616626 -197.741794)
		(width 0.20066)
		(layer "F.Cu")
		(net "M_B_CPU1_SB_DQ<28>")
	)
	(segment
		(start 45.859446 -198.166736)
		(end 44.490386 -198.166736)
		(width 0.20066)
		(layer "F.Cu")
		(net "M_B_CPU1_SB_DQ<28>")
	)
	(segment
		(start 40.347392 -198.405496)
		(end 39.888668 -198.405496)
		(width 0.20066)
		(layer "F.Cu")
		(net "M_B_CPU1_SB_DQ<28>")
	)
	(segment
		(start 85.421216 -223.575626)
		(end 85.421216 -223.561402)
		(width 0.088646)
		(layer "In4.Cu")
		(net "M_B_CPU1_SB_DQ<28>")
	)
	(segment
		(start 47.308516 -198.024242)
		(end 46.964346 -198.166736)
		(width 0.18288)
		(layer "In4.Cu")
		(net "M_B_CPU1_SB_DQ<28>")
	)
	(segment
		(start 82.960464 -221.268544)
		(end 82.708496 -221.268544)
		(width 0.088646)
		(layer "In4.Cu")
		(net "M_B_CPU1_SB_DQ<28>")
	)
	(segment
		(start 85.795866 -223.575626)
		(end 85.639402 -223.846644)
		(width 0.088646)
		(layer "In4.Cu")
		(net "M_B_CPU1_SB_DQ<28>")
	)
	(segment
		(start 64.606678 -196.891656)
		(end 50.042826 -196.891656)
		(width 0.18288)
		(layer "In4.Cu")
		(net "M_B_CPU1_SB_DQ<28>")
	)
	(segment
		(start 81.430114 -221.268544)
		(end 77.83703 -217.67546)
		(width 0.18288)
		(layer "In4.Cu")
		(net "M_B_CPU1_SB_DQ<28>")
	)
	(segment
		(start 84.118196 -222.263462)
		(end 84.103464 -222.272098)
		(width 0.088646)
		(layer "In4.Cu")
		(net "M_B_CPU1_SB_DQ<28>")
	)
	(segment
		(start 85.138514 -223.085914)
		(end 85.129624 -223.080834)
		(width 0.088646)
		(layer "In4.Cu")
		(net "M_B_CPU1_SB_DQ<28>")
	)
	(segment
		(start 83.769962 -222.322644)
		(end 83.16849 -221.721172)
		(width 0.088646)
		(layer "In4.Cu")
		(net "M_B_CPU1_SB_DQ<28>")
	)
	(segment
		(start 50.042826 -196.891656)
		(end 47.308516 -198.024242)
		(width 0.18288)
		(layer "In4.Cu")
		(net "M_B_CPU1_SB_DQ<28>")
	)
	(segment
		(start 85.639402 -223.846644)
		(end 85.56117 -223.867472)
		(width 0.088646)
		(layer "In4.Cu")
		(net "M_B_CPU1_SB_DQ<28>")
	)
	(segment
		(start 65.637156 -196.73062)
		(end 64.767714 -196.73062)
		(width 0.18288)
		(layer "In4.Cu")
		(net "M_B_CPU1_SB_DQ<28>")
	)
	(segment
		(start 83.916266 -222.322644)
		(end 83.769962 -222.322644)
		(width 0.088646)
		(layer "In4.Cu")
		(net "M_B_CPU1_SB_DQ<28>")
	)
	(segment
		(start 83.16849 -221.721172)
		(end 83.16849 -221.47657)
		(width 0.088646)
		(layer "In4.Cu")
		(net "M_B_CPU1_SB_DQ<28>")
	)
	(segment
		(start 72.145398 -203.934822)
		(end 68.089526 -199.87895)
		(width 0.18288)
		(layer "In4.Cu")
		(net "M_B_CPU1_SB_DQ<28>")
	)
	(segment
		(start 68.089526 -199.87895)
		(end 67.597528 -198.690992)
		(width 0.18288)
		(layer "In4.Cu")
		(net "M_B_CPU1_SB_DQ<28>")
	)
	(segment
		(start 64.767714 -196.73062)
		(end 64.606678 -196.891656)
		(width 0.18288)
		(layer "In4.Cu")
		(net "M_B_CPU1_SB_DQ<28>")
	)
	(segment
		(start 67.597528 -198.690992)
		(end 65.637156 -196.73062)
		(width 0.18288)
		(layer "In4.Cu")
		(net "M_B_CPU1_SB_DQ<28>")
	)
	(segment
		(start 84.951062 -222.761556)
		(end 84.951062 -222.746062)
		(width 0.088646)
		(layer "In4.Cu")
		(net "M_B_CPU1_SB_DQ<28>")
	)
	(segment
		(start 82.708496 -221.268544)
		(end 81.430114 -221.268544)
		(width 0.18288)
		(layer "In4.Cu")
		(net "M_B_CPU1_SB_DQ<28>")
	)
	(segment
		(start 83.16849 -221.47657)
		(end 82.960464 -221.268544)
		(width 0.088646)
		(layer "In4.Cu")
		(net "M_B_CPU1_SB_DQ<28>")
	)
	(segment
		(start 77.83703 -217.67546)
		(end 72.145398 -203.934822)
		(width 0.18288)
		(layer "In4.Cu")
		(net "M_B_CPU1_SB_DQ<28>")
	)
	(arc
		(start 84.951062 -222.746062)
		(mid 84.871692 -222.472328)
		(end 84.668868 -222.272098)
		(width 0.088646)
		(layer "In4.Cu")
		(net "M_B_CPU1_SB_DQ<28>")
	)
	(arc
		(start 85.56117 -223.867472)
		(mid 85.458025 -223.737447)
		(end 85.421216 -223.575626)
		(width 0.088646)
		(layer "In4.Cu")
		(net "M_B_CPU1_SB_DQ<28>")
	)
	(arc
		(start 84.668868 -222.272098)
		(mid 84.394669 -222.196263)
		(end 84.118196 -222.263462)
		(width 0.088646)
		(layer "In4.Cu")
		(net "M_B_CPU1_SB_DQ<28>")
	)
	(arc
		(start 84.103464 -222.272098)
		(mid 84.013192 -222.309697)
		(end 83.916266 -222.322644)
		(width 0.088646)
		(layer "In4.Cu")
		(net "M_B_CPU1_SB_DQ<28>")
	)
	(arc
		(start 85.421216 -223.561402)
		(mid 85.341997 -223.286717)
		(end 85.138514 -223.085914)
		(width 0.088646)
		(layer "In4.Cu")
		(net "M_B_CPU1_SB_DQ<28>")
	)
	(arc
		(start 85.129624 -223.080834)
		(mid 84.99871 -222.944474)
		(end 84.951062 -222.761556)
		(width 0.088646)
		(layer "In4.Cu")
		(net "M_B_CPU1_SB_DQ<28>")
	)
	(segment
		(start 49.143412 -201.56678)
		(end 48.935894 -201.774298)
		(width 0.20066)
		(layer "F.Cu")
		(net "M_B_CPU1_SB_DQ<27>")
	)
	(segment
		(start 44.735242 -202.005946)
		(end 44.38142 -202.005946)
		(width 0.20066)
		(layer "F.Cu")
		(net "M_B_CPU1_SB_DQ<27>")
	)
	(segment
		(start 44.38142 -202.005946)
		(end 44.238926 -201.863452)
		(width 0.20066)
		(layer "F.Cu")
		(net "M_B_CPU1_SB_DQ<27>")
	)
	(segment
		(start 87.205312 -226.553268)
		(end 87.205312 -226.017328)
		(width 0.20066)
		(layer "F.Cu")
		(net "M_B_CPU1_SB_DQ<27>")
	)
	(segment
		(start 44.112942 -201.56678)
		(end 42.415714 -201.56678)
		(width 0.20066)
		(layer "F.Cu")
		(net "M_B_CPU1_SB_DQ<27>")
	)
	(segment
		(start 51.064414 -201.56678)
		(end 49.959514 -201.56678)
		(width 0.20066)
		(layer "F.Cu")
		(net "M_B_CPU1_SB_DQ<27>")
	)
	(segment
		(start 47.753778 -201.842624)
		(end 47.60468 -201.991722)
		(width 0.20066)
		(layer "F.Cu")
		(net "M_B_CPU1_SB_DQ<27>")
	)
	(segment
		(start 49.959514 -201.56678)
		(end 49.143412 -201.56678)
		(width 0.20066)
		(layer "F.Cu")
		(net "M_B_CPU1_SB_DQ<27>")
	)
	(segment
		(start 48.277526 -201.562462)
		(end 47.882302 -201.562462)
		(width 0.20066)
		(layer "F.Cu")
		(net "M_B_CPU1_SB_DQ<27>")
	)
	(segment
		(start 48.489362 -201.774298)
		(end 48.277526 -201.562462)
		(width 0.20066)
		(layer "F.Cu")
		(net "M_B_CPU1_SB_DQ<27>")
	)
	(segment
		(start 44.238926 -201.692764)
		(end 44.112942 -201.56678)
		(width 0.20066)
		(layer "F.Cu")
		(net "M_B_CPU1_SB_DQ<27>")
	)
	(segment
		(start 47.753778 -201.690986)
		(end 47.753778 -201.842624)
		(width 0.20066)
		(layer "F.Cu")
		(net "M_B_CPU1_SB_DQ<27>")
	)
	(segment
		(start 47.060358 -201.991722)
		(end 44.987464 -201.991722)
		(width 0.1016)
		(layer "F.Cu")
		(net "M_B_CPU1_SB_DQ<27>")
	)
	(segment
		(start 44.749466 -201.991722)
		(end 44.735242 -202.005946)
		(width 0.101854)
		(layer "F.Cu")
		(net "M_B_CPU1_SB_DQ<27>")
	)
	(segment
		(start 47.882302 -201.562462)
		(end 47.753778 -201.690986)
		(width 0.20066)
		(layer "F.Cu")
		(net "M_B_CPU1_SB_DQ<27>")
	)
	(segment
		(start 44.238926 -201.863452)
		(end 44.238926 -201.692764)
		(width 0.20066)
		(layer "F.Cu")
		(net "M_B_CPU1_SB_DQ<27>")
	)
	(segment
		(start 44.987464 -201.991722)
		(end 44.749466 -201.991722)
		(width 0.101854)
		(layer "F.Cu")
		(net "M_B_CPU1_SB_DQ<27>")
	)
	(segment
		(start 47.60468 -201.991722)
		(end 47.060358 -201.991722)
		(width 0.20066)
		(layer "F.Cu")
		(net "M_B_CPU1_SB_DQ<27>")
	)
	(segment
		(start 48.935894 -201.774298)
		(end 48.489362 -201.774298)
		(width 0.20066)
		(layer "F.Cu")
		(net "M_B_CPU1_SB_DQ<27>")
	)
	(segment
		(start 56.751982 -201.444098)
		(end 55.252366 -201.444098)
		(width 0.18288)
		(layer "In4.Cu")
		(net "M_B_CPU1_SB_DQ<27>")
	)
	(segment
		(start 64.310768 -201.798428)
		(end 64.052196 -201.798428)
		(width 0.18288)
		(layer "In4.Cu")
		(net "M_B_CPU1_SB_DQ<27>")
	)
	(segment
		(start 60.396374 -200.634854)
		(end 59.385708 -200.634854)
		(width 0.18288)
		(layer "In4.Cu")
		(net "M_B_CPU1_SB_DQ<27>")
	)
	(segment
		(start 64.052196 -201.798428)
		(end 63.939928 -201.910696)
		(width 0.18288)
		(layer "In4.Cu")
		(net "M_B_CPU1_SB_DQ<27>")
	)
	(segment
		(start 65.431416 -202.919076)
		(end 64.310768 -201.798428)
		(width 0.18288)
		(layer "In4.Cu")
		(net "M_B_CPU1_SB_DQ<27>")
	)
	(segment
		(start 51.53406 -202.036426)
		(end 51.064414 -201.56678)
		(width 0.18288)
		(layer "In4.Cu")
		(net "M_B_CPU1_SB_DQ<27>")
	)
	(segment
		(start 84.067396 -225.325686)
		(end 84.067396 -225.113596)
		(width 0.088646)
		(layer "In4.Cu")
		(net "M_B_CPU1_SB_DQ<27>")
	)
	(segment
		(start 58.42889 -201.274426)
		(end 57.841896 -200.687432)
		(width 0.18288)
		(layer "In4.Cu")
		(net "M_B_CPU1_SB_DQ<27>")
	)
	(segment
		(start 53.933598 -202.036426)
		(end 53.750718 -201.853546)
		(width 0.18288)
		(layer "In4.Cu")
		(net "M_B_CPU1_SB_DQ<27>")
	)
	(segment
		(start 53.750718 -201.621898)
		(end 53.567838 -201.439018)
		(width 0.18288)
		(layer "In4.Cu")
		(net "M_B_CPU1_SB_DQ<27>")
	)
	(segment
		(start 61.270134 -200.817734)
		(end 61.270134 -201.395076)
		(width 0.18288)
		(layer "In4.Cu")
		(net "M_B_CPU1_SB_DQ<27>")
	)
	(segment
		(start 63.451232 -201.680572)
		(end 63.451232 -201.422)
		(width 0.18288)
		(layer "In4.Cu")
		(net "M_B_CPU1_SB_DQ<27>")
	)
	(segment
		(start 57.072022 -200.687432)
		(end 56.912002 -200.847452)
		(width 0.18288)
		(layer "In4.Cu")
		(net "M_B_CPU1_SB_DQ<27>")
	)
	(segment
		(start 55.092346 -201.604118)
		(end 55.092346 -201.876406)
		(width 0.18288)
		(layer "In4.Cu")
		(net "M_B_CPU1_SB_DQ<27>")
	)
	(segment
		(start 80.170782 -223.897952)
		(end 75.416664 -219.143834)
		(width 0.18288)
		(layer "In4.Cu")
		(net "M_B_CPU1_SB_DQ<27>")
	)
	(segment
		(start 63.5635 -201.05116)
		(end 63.147194 -200.634854)
		(width 0.18288)
		(layer "In4.Cu")
		(net "M_B_CPU1_SB_DQ<27>")
	)
	(segment
		(start 58.746136 -201.274426)
		(end 58.42889 -201.274426)
		(width 0.18288)
		(layer "In4.Cu")
		(net "M_B_CPU1_SB_DQ<27>")
	)
	(segment
		(start 53.242718 -201.439018)
		(end 53.059838 -201.621898)
		(width 0.18288)
		(layer "In4.Cu")
		(net "M_B_CPU1_SB_DQ<27>")
	)
	(segment
		(start 52.876958 -202.036426)
		(end 51.53406 -202.036426)
		(width 0.18288)
		(layer "In4.Cu")
		(net "M_B_CPU1_SB_DQ<27>")
	)
	(segment
		(start 69.890386 -205.802992)
		(end 67.00647 -202.919076)
		(width 0.18288)
		(layer "In4.Cu")
		(net "M_B_CPU1_SB_DQ<27>")
	)
	(segment
		(start 85.138768 -225.69297)
		(end 84.934552 -225.81108)
		(width 0.088646)
		(layer "In4.Cu")
		(net "M_B_CPU1_SB_DQ<27>")
	)
	(segment
		(start 54.932326 -202.036426)
		(end 53.933598 -202.036426)
		(width 0.18288)
		(layer "In4.Cu")
		(net "M_B_CPU1_SB_DQ<27>")
	)
	(segment
		(start 56.912002 -200.847452)
		(end 56.912002 -201.284078)
		(width 0.18288)
		(layer "In4.Cu")
		(net "M_B_CPU1_SB_DQ<27>")
	)
	(segment
		(start 75.416664 -219.143834)
		(end 69.890386 -205.802992)
		(width 0.18288)
		(layer "In4.Cu")
		(net "M_B_CPU1_SB_DQ<27>")
	)
	(segment
		(start 61.270134 -201.395076)
		(end 61.087254 -201.577956)
		(width 0.18288)
		(layer "In4.Cu")
		(net "M_B_CPU1_SB_DQ<27>")
	)
	(segment
		(start 84.067396 -225.113596)
		(end 82.851752 -223.897952)
		(width 0.088646)
		(layer "In4.Cu")
		(net "M_B_CPU1_SB_DQ<27>")
	)
	(segment
		(start 82.851752 -223.897952)
		(end 82.708496 -223.897952)
		(width 0.088646)
		(layer "In4.Cu")
		(net "M_B_CPU1_SB_DQ<27>")
	)
	(segment
		(start 53.059838 -201.621898)
		(end 53.059838 -201.853546)
		(width 0.18288)
		(layer "In4.Cu")
		(net "M_B_CPU1_SB_DQ<27>")
	)
	(segment
		(start 63.681356 -201.910696)
		(end 63.451232 -201.680572)
		(width 0.18288)
		(layer "In4.Cu")
		(net "M_B_CPU1_SB_DQ<27>")
	)
	(segment
		(start 61.453014 -200.634854)
		(end 61.270134 -200.817734)
		(width 0.18288)
		(layer "In4.Cu")
		(net "M_B_CPU1_SB_DQ<27>")
	)
	(segment
		(start 61.087254 -201.577956)
		(end 60.762134 -201.577956)
		(width 0.18288)
		(layer "In4.Cu")
		(net "M_B_CPU1_SB_DQ<27>")
	)
	(segment
		(start 60.762134 -201.577956)
		(end 60.579254 -201.395076)
		(width 0.18288)
		(layer "In4.Cu")
		(net "M_B_CPU1_SB_DQ<27>")
	)
	(segment
		(start 67.00647 -202.919076)
		(end 65.431416 -202.919076)
		(width 0.18288)
		(layer "In4.Cu")
		(net "M_B_CPU1_SB_DQ<27>")
	)
	(segment
		(start 86.85149 -225.922586)
		(end 86.447122 -225.689414)
		(width 0.088646)
		(layer "In4.Cu")
		(net "M_B_CPU1_SB_DQ<27>")
	)
	(segment
		(start 84.55279 -225.81108)
		(end 84.067396 -225.325686)
		(width 0.088646)
		(layer "In4.Cu")
		(net "M_B_CPU1_SB_DQ<27>")
	)
	(segment
		(start 59.385708 -200.634854)
		(end 58.746136 -201.274426)
		(width 0.18288)
		(layer "In4.Cu")
		(net "M_B_CPU1_SB_DQ<27>")
	)
	(segment
		(start 84.934552 -225.81108)
		(end 84.55279 -225.81108)
		(width 0.088646)
		(layer "In4.Cu")
		(net "M_B_CPU1_SB_DQ<27>")
	)
	(segment
		(start 53.750718 -201.853546)
		(end 53.750718 -201.621898)
		(width 0.18288)
		(layer "In4.Cu")
		(net "M_B_CPU1_SB_DQ<27>")
	)
	(segment
		(start 60.579254 -200.817734)
		(end 60.396374 -200.634854)
		(width 0.18288)
		(layer "In4.Cu")
		(net "M_B_CPU1_SB_DQ<27>")
	)
	(segment
		(start 63.939928 -201.910696)
		(end 63.681356 -201.910696)
		(width 0.18288)
		(layer "In4.Cu")
		(net "M_B_CPU1_SB_DQ<27>")
	)
	(segment
		(start 53.567838 -201.439018)
		(end 53.242718 -201.439018)
		(width 0.18288)
		(layer "In4.Cu")
		(net "M_B_CPU1_SB_DQ<27>")
	)
	(segment
		(start 60.579254 -201.395076)
		(end 60.579254 -200.817734)
		(width 0.18288)
		(layer "In4.Cu")
		(net "M_B_CPU1_SB_DQ<27>")
	)
	(segment
		(start 63.5635 -201.309732)
		(end 63.5635 -201.05116)
		(width 0.18288)
		(layer "In4.Cu")
		(net "M_B_CPU1_SB_DQ<27>")
	)
	(segment
		(start 57.841896 -200.687432)
		(end 57.072022 -200.687432)
		(width 0.18288)
		(layer "In4.Cu")
		(net "M_B_CPU1_SB_DQ<27>")
	)
	(segment
		(start 53.059838 -201.853546)
		(end 52.876958 -202.036426)
		(width 0.18288)
		(layer "In4.Cu")
		(net "M_B_CPU1_SB_DQ<27>")
	)
	(segment
		(start 56.912002 -201.284078)
		(end 56.751982 -201.444098)
		(width 0.18288)
		(layer "In4.Cu")
		(net "M_B_CPU1_SB_DQ<27>")
	)
	(segment
		(start 55.092346 -201.876406)
		(end 54.932326 -202.036426)
		(width 0.18288)
		(layer "In4.Cu")
		(net "M_B_CPU1_SB_DQ<27>")
	)
	(segment
		(start 63.451232 -201.422)
		(end 63.5635 -201.309732)
		(width 0.18288)
		(layer "In4.Cu")
		(net "M_B_CPU1_SB_DQ<27>")
	)
	(segment
		(start 63.147194 -200.634854)
		(end 61.453014 -200.634854)
		(width 0.18288)
		(layer "In4.Cu")
		(net "M_B_CPU1_SB_DQ<27>")
	)
	(segment
		(start 55.252366 -201.444098)
		(end 55.092346 -201.604118)
		(width 0.18288)
		(layer "In4.Cu")
		(net "M_B_CPU1_SB_DQ<27>")
	)
	(segment
		(start 82.708496 -223.897952)
		(end 80.170782 -223.897952)
		(width 0.18288)
		(layer "In4.Cu")
		(net "M_B_CPU1_SB_DQ<27>")
	)
	(arc
		(start 87.205312 -226.017328)
		(mid 87.022195 -225.993152)
		(end 86.85149 -225.922586)
		(width 0.088646)
		(layer "In4.Cu")
		(net "M_B_CPU1_SB_DQ<27>")
	)
	(arc
		(start 86.447122 -225.689414)
		(mid 86.262267 -225.642496)
		(end 86.078314 -225.692716)
		(width 0.088646)
		(layer "In4.Cu")
		(net "M_B_CPU1_SB_DQ<27>")
	)
	(arc
		(start 86.078314 -225.692716)
		(mid 85.795895 -225.768526)
		(end 85.513418 -225.69297)
		(width 0.088646)
		(layer "In4.Cu")
		(net "M_B_CPU1_SB_DQ<27>")
	)
	(arc
		(start 85.513418 -225.69297)
		(mid 85.326076 -225.642734)
		(end 85.138768 -225.69297)
		(width 0.088646)
		(layer "In4.Cu")
		(net "M_B_CPU1_SB_DQ<27>")
	)
	(segment
		(start 48.432974 -203.478638)
		(end 48.004476 -203.478638)
		(width 0.20066)
		(layer "F.Cu")
		(net "M_B_CPU1_SB_DQ<26>")
	)
	(segment
		(start 47.060358 -202.84186)
		(end 45.000418 -202.84186)
		(width 0.1016)
		(layer "F.Cu")
		(net "M_B_CPU1_SB_DQ<26>")
	)
	(segment
		(start 44.745402 -202.84186)
		(end 44.735242 -202.8317)
		(width 0.101854)
		(layer "F.Cu")
		(net "M_B_CPU1_SB_DQ<26>")
	)
	(segment
		(start 48.004476 -203.478638)
		(end 47.83709 -203.311252)
		(width 0.20066)
		(layer "F.Cu")
		(net "M_B_CPU1_SB_DQ<26>")
	)
	(segment
		(start 43.562778 -203.266802)
		(end 42.415714 -203.266802)
		(width 0.20066)
		(layer "F.Cu")
		(net "M_B_CPU1_SB_DQ<26>")
	)
	(segment
		(start 49.959514 -203.266802)
		(end 48.64481 -203.266802)
		(width 0.20066)
		(layer "F.Cu")
		(net "M_B_CPU1_SB_DQ<26>")
	)
	(segment
		(start 47.693326 -202.84186)
		(end 47.060358 -202.84186)
		(width 0.20066)
		(layer "F.Cu")
		(net "M_B_CPU1_SB_DQ<26>")
	)
	(segment
		(start 47.83709 -203.311252)
		(end 47.83709 -202.985624)
		(width 0.20066)
		(layer "F.Cu")
		(net "M_B_CPU1_SB_DQ<26>")
	)
	(segment
		(start 45.000418 -202.84186)
		(end 44.745402 -202.84186)
		(width 0.101854)
		(layer "F.Cu")
		(net "M_B_CPU1_SB_DQ<26>")
	)
	(segment
		(start 47.83709 -202.985624)
		(end 47.693326 -202.84186)
		(width 0.20066)
		(layer "F.Cu")
		(net "M_B_CPU1_SB_DQ<26>")
	)
	(segment
		(start 51.064414 -203.266802)
		(end 49.959514 -203.266802)
		(width 0.20066)
		(layer "F.Cu")
		(net "M_B_CPU1_SB_DQ<26>")
	)
	(segment
		(start 44.735242 -202.8317)
		(end 43.99788 -202.8317)
		(width 0.20066)
		(layer "F.Cu")
		(net "M_B_CPU1_SB_DQ<26>")
	)
	(segment
		(start 43.99788 -202.8317)
		(end 43.562778 -203.266802)
		(width 0.20066)
		(layer "F.Cu")
		(net "M_B_CPU1_SB_DQ<26>")
	)
	(segment
		(start 86.735666 -226.831398)
		(end 86.735412 -226.831144)
		(width 0.20066)
		(layer "F.Cu")
		(net "M_B_CPU1_SB_DQ<26>")
	)
	(segment
		(start 48.64481 -203.266802)
		(end 48.432974 -203.478638)
		(width 0.20066)
		(layer "F.Cu")
		(net "M_B_CPU1_SB_DQ<26>")
	)
	(segment
		(start 86.735666 -227.367084)
		(end 86.735666 -226.831398)
		(width 0.20066)
		(layer "F.Cu")
		(net "M_B_CPU1_SB_DQ<26>")
	)
	(segment
		(start 86.078568 -226.341686)
		(end 86.068154 -226.33559)
		(width 0.088646)
		(layer "In4.Cu")
		(net "M_B_CPU1_SB_DQ<26>")
	)
	(segment
		(start 82.708496 -224.893632)
		(end 79.58709 -224.893632)
		(width 0.18288)
		(layer "In4.Cu")
		(net "M_B_CPU1_SB_DQ<26>")
	)
	(segment
		(start 62.447932 -202.712066)
		(end 61.598302 -202.712066)
		(width 0.18288)
		(layer "In4.Cu")
		(net "M_B_CPU1_SB_DQ<26>")
	)
	(segment
		(start 55.120286 -203.452984)
		(end 54.774338 -203.798932)
		(width 0.18288)
		(layer "In4.Cu")
		(net "M_B_CPU1_SB_DQ<26>")
	)
	(segment
		(start 53.61178 -203.616052)
		(end 53.61178 -203.358496)
		(width 0.18288)
		(layer "In4.Cu")
		(net "M_B_CPU1_SB_DQ<26>")
	)
	(segment
		(start 67.008502 -204.627226)
		(end 65.168526 -204.627226)
		(width 0.18288)
		(layer "In4.Cu")
		(net "M_B_CPU1_SB_DQ<26>")
	)
	(segment
		(start 53.61178 -203.358496)
		(end 53.4289 -203.175616)
		(width 0.18288)
		(layer "In4.Cu")
		(net "M_B_CPU1_SB_DQ<26>")
	)
	(segment
		(start 58.382662 -202.975464)
		(end 58.199782 -202.792584)
		(width 0.18288)
		(layer "In4.Cu")
		(net "M_B_CPU1_SB_DQ<26>")
	)
	(segment
		(start 58.894472 -203.452984)
		(end 58.565542 -203.452984)
		(width 0.18288)
		(layer "In4.Cu")
		(net "M_B_CPU1_SB_DQ<26>")
	)
	(segment
		(start 64.16167 -203.62037)
		(end 62.91707 -203.62037)
		(width 0.18288)
		(layer "In4.Cu")
		(net "M_B_CPU1_SB_DQ<26>")
	)
	(segment
		(start 62.91707 -203.62037)
		(end 62.70498 -203.40828)
		(width 0.18288)
		(layer "In4.Cu")
		(net "M_B_CPU1_SB_DQ<26>")
	)
	(segment
		(start 54.774338 -203.798932)
		(end 53.79466 -203.798932)
		(width 0.18288)
		(layer "In4.Cu")
		(net "M_B_CPU1_SB_DQ<26>")
	)
	(segment
		(start 58.565542 -203.452984)
		(end 58.382662 -203.270104)
		(width 0.18288)
		(layer "In4.Cu")
		(net "M_B_CPU1_SB_DQ<26>")
	)
	(segment
		(start 52.73802 -203.798932)
		(end 52.158138 -203.798932)
		(width 0.18288)
		(layer "In4.Cu")
		(net "M_B_CPU1_SB_DQ<26>")
	)
	(segment
		(start 86.735412 -226.831144)
		(end 86.422738 -226.831144)
		(width 0.088646)
		(layer "In4.Cu")
		(net "M_B_CPU1_SB_DQ<26>")
	)
	(segment
		(start 60.724542 -202.894946)
		(end 60.541662 -202.712066)
		(width 0.18288)
		(layer "In4.Cu")
		(net "M_B_CPU1_SB_DQ<26>")
	)
	(segment
		(start 61.598302 -202.712066)
		(end 61.415422 -202.894946)
		(width 0.18288)
		(layer "In4.Cu")
		(net "M_B_CPU1_SB_DQ<26>")
	)
	(segment
		(start 57.000902 -203.930504)
		(end 57.000902 -203.635864)
		(width 0.18288)
		(layer "In4.Cu")
		(net "M_B_CPU1_SB_DQ<26>")
	)
	(segment
		(start 59.22645 -202.872086)
		(end 59.22645 -203.121006)
		(width 0.18288)
		(layer "In4.Cu")
		(net "M_B_CPU1_SB_DQ<26>")
	)
	(segment
		(start 60.541662 -202.712066)
		(end 59.38647 -202.712066)
		(width 0.18288)
		(layer "In4.Cu")
		(net "M_B_CPU1_SB_DQ<26>")
	)
	(segment
		(start 74.69251 -219.999052)
		(end 69.256402 -206.875126)
		(width 0.18288)
		(layer "In4.Cu")
		(net "M_B_CPU1_SB_DQ<26>")
	)
	(segment
		(start 65.168526 -204.627226)
		(end 64.16167 -203.62037)
		(width 0.18288)
		(layer "In4.Cu")
		(net "M_B_CPU1_SB_DQ<26>")
	)
	(segment
		(start 53.10378 -203.175616)
		(end 52.9209 -203.358496)
		(width 0.18288)
		(layer "In4.Cu")
		(net "M_B_CPU1_SB_DQ<26>")
	)
	(segment
		(start 58.382662 -203.270104)
		(end 58.382662 -202.975464)
		(width 0.18288)
		(layer "In4.Cu")
		(net "M_B_CPU1_SB_DQ<26>")
	)
	(segment
		(start 57.000902 -203.635864)
		(end 56.818022 -203.452984)
		(width 0.18288)
		(layer "In4.Cu")
		(net "M_B_CPU1_SB_DQ<26>")
	)
	(segment
		(start 57.691782 -202.975464)
		(end 57.691782 -203.930504)
		(width 0.18288)
		(layer "In4.Cu")
		(net "M_B_CPU1_SB_DQ<26>")
	)
	(segment
		(start 61.232542 -203.891388)
		(end 60.907422 -203.891388)
		(width 0.18288)
		(layer "In4.Cu")
		(net "M_B_CPU1_SB_DQ<26>")
	)
	(segment
		(start 61.415422 -202.894946)
		(end 61.415422 -203.708508)
		(width 0.18288)
		(layer "In4.Cu")
		(net "M_B_CPU1_SB_DQ<26>")
	)
	(segment
		(start 60.724542 -203.708508)
		(end 60.724542 -202.894946)
		(width 0.18288)
		(layer "In4.Cu")
		(net "M_B_CPU1_SB_DQ<26>")
	)
	(segment
		(start 58.199782 -202.792584)
		(end 57.874662 -202.792584)
		(width 0.18288)
		(layer "In4.Cu")
		(net "M_B_CPU1_SB_DQ<26>")
	)
	(segment
		(start 53.79466 -203.798932)
		(end 53.61178 -203.616052)
		(width 0.18288)
		(layer "In4.Cu")
		(net "M_B_CPU1_SB_DQ<26>")
	)
	(segment
		(start 59.38647 -202.712066)
		(end 59.22645 -202.872086)
		(width 0.18288)
		(layer "In4.Cu")
		(net "M_B_CPU1_SB_DQ<26>")
	)
	(segment
		(start 69.256402 -206.875126)
		(end 67.008502 -204.627226)
		(width 0.18288)
		(layer "In4.Cu")
		(net "M_B_CPU1_SB_DQ<26>")
	)
	(segment
		(start 59.22645 -203.121006)
		(end 58.894472 -203.452984)
		(width 0.18288)
		(layer "In4.Cu")
		(net "M_B_CPU1_SB_DQ<26>")
	)
	(segment
		(start 57.508902 -204.113384)
		(end 57.183782 -204.113384)
		(width 0.18288)
		(layer "In4.Cu")
		(net "M_B_CPU1_SB_DQ<26>")
	)
	(segment
		(start 52.9209 -203.358496)
		(end 52.9209 -203.616052)
		(width 0.18288)
		(layer "In4.Cu")
		(net "M_B_CPU1_SB_DQ<26>")
	)
	(segment
		(start 62.70498 -203.40828)
		(end 62.70498 -202.969114)
		(width 0.18288)
		(layer "In4.Cu")
		(net "M_B_CPU1_SB_DQ<26>")
	)
	(segment
		(start 60.907422 -203.891388)
		(end 60.724542 -203.708508)
		(width 0.18288)
		(layer "In4.Cu")
		(net "M_B_CPU1_SB_DQ<26>")
	)
	(segment
		(start 57.874662 -202.792584)
		(end 57.691782 -202.975464)
		(width 0.18288)
		(layer "In4.Cu")
		(net "M_B_CPU1_SB_DQ<26>")
	)
	(segment
		(start 82.933286 -224.893632)
		(end 82.708496 -224.893632)
		(width 0.088646)
		(layer "In4.Cu")
		(net "M_B_CPU1_SB_DQ<26>")
	)
	(segment
		(start 57.691782 -203.930504)
		(end 57.508902 -204.113384)
		(width 0.18288)
		(layer "In4.Cu")
		(net "M_B_CPU1_SB_DQ<26>")
	)
	(segment
		(start 62.70498 -202.969114)
		(end 62.447932 -202.712066)
		(width 0.18288)
		(layer "In4.Cu")
		(net "M_B_CPU1_SB_DQ<26>")
	)
	(segment
		(start 56.818022 -203.452984)
		(end 55.120286 -203.452984)
		(width 0.18288)
		(layer "In4.Cu")
		(net "M_B_CPU1_SB_DQ<26>")
	)
	(segment
		(start 84.370926 -226.331272)
		(end 82.933286 -224.893632)
		(width 0.088646)
		(layer "In4.Cu")
		(net "M_B_CPU1_SB_DQ<26>")
	)
	(segment
		(start 79.58709 -224.893632)
		(end 74.69251 -219.999052)
		(width 0.18288)
		(layer "In4.Cu")
		(net "M_B_CPU1_SB_DQ<26>")
	)
	(segment
		(start 61.415422 -203.708508)
		(end 61.232542 -203.891388)
		(width 0.18288)
		(layer "In4.Cu")
		(net "M_B_CPU1_SB_DQ<26>")
	)
	(segment
		(start 57.183782 -204.113384)
		(end 57.000902 -203.930504)
		(width 0.18288)
		(layer "In4.Cu")
		(net "M_B_CPU1_SB_DQ<26>")
	)
	(segment
		(start 86.422738 -226.831144)
		(end 86.35746 -226.765866)
		(width 0.088646)
		(layer "In4.Cu")
		(net "M_B_CPU1_SB_DQ<26>")
	)
	(segment
		(start 53.4289 -203.175616)
		(end 53.10378 -203.175616)
		(width 0.18288)
		(layer "In4.Cu")
		(net "M_B_CPU1_SB_DQ<26>")
	)
	(segment
		(start 84.5312 -226.331272)
		(end 84.370926 -226.331272)
		(width 0.088646)
		(layer "In4.Cu")
		(net "M_B_CPU1_SB_DQ<26>")
	)
	(segment
		(start 52.158138 -203.798932)
		(end 51.626008 -203.266802)
		(width 0.18288)
		(layer "In4.Cu")
		(net "M_B_CPU1_SB_DQ<26>")
	)
	(segment
		(start 51.626008 -203.266802)
		(end 51.064414 -203.266802)
		(width 0.18288)
		(layer "In4.Cu")
		(net "M_B_CPU1_SB_DQ<26>")
	)
	(segment
		(start 52.9209 -203.616052)
		(end 52.73802 -203.798932)
		(width 0.18288)
		(layer "In4.Cu")
		(net "M_B_CPU1_SB_DQ<26>")
	)
	(arc
		(start 84.61883 -226.31654)
		(mid 84.575636 -226.327597)
		(end 84.5312 -226.331272)
		(width 0.088646)
		(layer "In4.Cu")
		(net "M_B_CPU1_SB_DQ<26>")
	)
	(arc
		(start 86.068154 -226.33559)
		(mid 85.789722 -226.265744)
		(end 85.51291 -226.341686)
		(width 0.088646)
		(layer "In4.Cu")
		(net "M_B_CPU1_SB_DQ<26>")
	)
	(arc
		(start 86.35746 -226.765866)
		(mid 86.268331 -226.520691)
		(end 86.078568 -226.341686)
		(width 0.088646)
		(layer "In4.Cu")
		(net "M_B_CPU1_SB_DQ<26>")
	)
	(arc
		(start 85.51291 -226.341686)
		(mid 85.325712 -226.391829)
		(end 85.138514 -226.341686)
		(width 0.088646)
		(layer "In4.Cu")
		(net "M_B_CPU1_SB_DQ<26>")
	)
	(arc
		(start 85.138514 -226.341686)
		(mid 84.895397 -226.267298)
		(end 84.64423 -226.306888)
		(width 0.088646)
		(layer "In4.Cu")
		(net "M_B_CPU1_SB_DQ<26>")
	)
	(arc
		(start 84.64423 -226.306888)
		(mid 84.631588 -226.311867)
		(end 84.61883 -226.31654)
		(width 0.088646)
		(layer "In4.Cu")
		(net "M_B_CPU1_SB_DQ<26>")
	)
	(segment
		(start 39.861236 -202.627992)
		(end 39.649908 -202.416664)
		(width 0.20066)
		(layer "F.Cu")
		(net "M_B_CPU1_SB_DQ<25>")
	)
	(segment
		(start 40.36568 -202.627992)
		(end 39.861236 -202.627992)
		(width 0.20066)
		(layer "F.Cu")
		(net "M_B_CPU1_SB_DQ<25>")
	)
	(segment
		(start 41.3004 -201.991722)
		(end 41.29151 -201.982832)
		(width 0.1016)
		(layer "F.Cu")
		(net "M_B_CPU1_SB_DQ<25>")
	)
	(segment
		(start 40.520112 -202.145392)
		(end 40.520112 -202.47356)
		(width 0.20066)
		(layer "F.Cu")
		(net "M_B_CPU1_SB_DQ<25>")
	)
	(segment
		(start 43.285918 -201.991722)
		(end 41.3004 -201.991722)
		(width 0.1016)
		(layer "F.Cu")
		(net "M_B_CPU1_SB_DQ<25>")
	)
	(segment
		(start 43.616626 -201.991722)
		(end 43.285918 -201.991722)
		(width 0.101854)
		(layer "F.Cu")
		(net "M_B_CPU1_SB_DQ<25>")
	)
	(segment
		(start 40.682672 -201.982832)
		(end 40.520112 -202.145392)
		(width 0.20066)
		(layer "F.Cu")
		(net "M_B_CPU1_SB_DQ<25>")
	)
	(segment
		(start 40.520112 -202.47356)
		(end 40.36568 -202.627992)
		(width 0.20066)
		(layer "F.Cu")
		(net "M_B_CPU1_SB_DQ<25>")
	)
	(segment
		(start 39.649908 -202.416664)
		(end 38.315646 -202.416664)
		(width 0.20066)
		(layer "F.Cu")
		(net "M_B_CPU1_SB_DQ<25>")
	)
	(segment
		(start 44.22013 -202.416664)
		(end 43.795188 -201.991722)
		(width 0.20066)
		(layer "F.Cu")
		(net "M_B_CPU1_SB_DQ<25>")
	)
	(segment
		(start 43.795188 -201.991722)
		(end 43.616626 -201.991722)
		(width 0.20066)
		(layer "F.Cu")
		(net "M_B_CPU1_SB_DQ<25>")
	)
	(segment
		(start 85.325712 -226.553268)
		(end 85.325712 -226.017328)
		(width 0.20066)
		(layer "F.Cu")
		(net "M_B_CPU1_SB_DQ<25>")
	)
	(segment
		(start 45.859446 -202.416664)
		(end 44.22013 -202.416664)
		(width 0.20066)
		(layer "F.Cu")
		(net "M_B_CPU1_SB_DQ<25>")
	)
	(segment
		(start 41.29151 -201.982832)
		(end 40.682672 -201.982832)
		(width 0.20066)
		(layer "F.Cu")
		(net "M_B_CPU1_SB_DQ<25>")
	)
	(segment
		(start 46.964346 -202.416664)
		(end 45.859446 -202.416664)
		(width 0.20066)
		(layer "F.Cu")
		(net "M_B_CPU1_SB_DQ<25>")
	)
	(segment
		(start 82.98815 -224.395792)
		(end 82.708496 -224.395792)
		(width 0.088646)
		(layer "In4.Cu")
		(net "M_B_CPU1_SB_DQ<25>")
	)
	(segment
		(start 51.26736 -202.84186)
		(end 50.518822 -202.84186)
		(width 0.18288)
		(layer "In4.Cu")
		(net "M_B_CPU1_SB_DQ<25>")
	)
	(segment
		(start 49.827942 -203.521564)
		(end 49.645062 -203.338684)
		(width 0.18288)
		(layer "In4.Cu")
		(net "M_B_CPU1_SB_DQ<25>")
	)
	(segment
		(start 53.426106 -202.544426)
		(end 53.335936 -202.634596)
		(width 0.18288)
		(layer "In4.Cu")
		(net "M_B_CPU1_SB_DQ<25>")
	)
	(segment
		(start 75.07224 -219.614496)
		(end 69.574918 -206.342742)
		(width 0.18288)
		(layer "In4.Cu")
		(net "M_B_CPU1_SB_DQ<25>")
	)
	(segment
		(start 63.502794 -203.00823)
		(end 63.265812 -202.771248)
		(width 0.18288)
		(layer "In4.Cu")
		(net "M_B_CPU1_SB_DQ<25>")
	)
	(segment
		(start 49.645062 -203.02474)
		(end 49.462182 -202.84186)
		(width 0.18288)
		(layer "In4.Cu")
		(net "M_B_CPU1_SB_DQ<25>")
	)
	(segment
		(start 84.411566 -226.017328)
		(end 83.72602 -225.331782)
		(width 0.088646)
		(layer "In4.Cu")
		(net "M_B_CPU1_SB_DQ<25>")
	)
	(segment
		(start 50.153062 -203.521564)
		(end 49.827942 -203.521564)
		(width 0.18288)
		(layer "In4.Cu")
		(net "M_B_CPU1_SB_DQ<25>")
	)
	(segment
		(start 63.265812 -202.310492)
		(end 63.053468 -202.098148)
		(width 0.18288)
		(layer "In4.Cu")
		(net "M_B_CPU1_SB_DQ<25>")
	)
	(segment
		(start 83.72602 -225.133662)
		(end 82.98815 -224.395792)
		(width 0.088646)
		(layer "In4.Cu")
		(net "M_B_CPU1_SB_DQ<25>")
	)
	(segment
		(start 51.474624 -202.634596)
		(end 51.26736 -202.84186)
		(width 0.18288)
		(layer "In4.Cu")
		(net "M_B_CPU1_SB_DQ<25>")
	)
	(segment
		(start 49.137062 -202.84186)
		(end 48.954182 -203.02474)
		(width 0.18288)
		(layer "In4.Cu")
		(net "M_B_CPU1_SB_DQ<25>")
	)
	(segment
		(start 63.265812 -202.771248)
		(end 63.265812 -202.310492)
		(width 0.18288)
		(layer "In4.Cu")
		(net "M_B_CPU1_SB_DQ<25>")
	)
	(segment
		(start 48.080422 -202.84186)
		(end 47.389542 -202.84186)
		(width 0.18288)
		(layer "In4.Cu")
		(net "M_B_CPU1_SB_DQ<25>")
	)
	(segment
		(start 50.335942 -203.02474)
		(end 50.335942 -203.338684)
		(width 0.18288)
		(layer "In4.Cu")
		(net "M_B_CPU1_SB_DQ<25>")
	)
	(segment
		(start 57.26938 -202.186032)
		(end 56.504586 -202.950826)
		(width 0.18288)
		(layer "In4.Cu")
		(net "M_B_CPU1_SB_DQ<25>")
	)
	(segment
		(start 48.263302 -203.02474)
		(end 48.080422 -202.84186)
		(width 0.18288)
		(layer "In4.Cu")
		(net "M_B_CPU1_SB_DQ<25>")
	)
	(segment
		(start 64.47409 -203.00823)
		(end 63.502794 -203.00823)
		(width 0.18288)
		(layer "In4.Cu")
		(net "M_B_CPU1_SB_DQ<25>")
	)
	(segment
		(start 48.771302 -203.521564)
		(end 48.446182 -203.521564)
		(width 0.18288)
		(layer "In4.Cu")
		(net "M_B_CPU1_SB_DQ<25>")
	)
	(segment
		(start 59.349894 -201.91222)
		(end 58.241438 -201.91222)
		(width 0.18288)
		(layer "In4.Cu")
		(net "M_B_CPU1_SB_DQ<25>")
	)
	(segment
		(start 48.446182 -203.521564)
		(end 48.263302 -203.338684)
		(width 0.18288)
		(layer "In4.Cu")
		(net "M_B_CPU1_SB_DQ<25>")
	)
	(segment
		(start 57.967626 -202.186032)
		(end 57.26938 -202.186032)
		(width 0.18288)
		(layer "In4.Cu")
		(net "M_B_CPU1_SB_DQ<25>")
	)
	(segment
		(start 66.767202 -203.535026)
		(end 65.000886 -203.535026)
		(width 0.18288)
		(layer "In4.Cu")
		(net "M_B_CPU1_SB_DQ<25>")
	)
	(segment
		(start 49.462182 -202.84186)
		(end 49.137062 -202.84186)
		(width 0.18288)
		(layer "In4.Cu")
		(net "M_B_CPU1_SB_DQ<25>")
	)
	(segment
		(start 49.645062 -203.338684)
		(end 49.645062 -203.02474)
		(width 0.18288)
		(layer "In4.Cu")
		(net "M_B_CPU1_SB_DQ<25>")
	)
	(segment
		(start 53.335936 -202.634596)
		(end 51.474624 -202.634596)
		(width 0.18288)
		(layer "In4.Cu")
		(net "M_B_CPU1_SB_DQ<25>")
	)
	(segment
		(start 79.853536 -224.395792)
		(end 75.07224 -219.614496)
		(width 0.18288)
		(layer "In4.Cu")
		(net "M_B_CPU1_SB_DQ<25>")
	)
	(segment
		(start 82.708496 -224.395792)
		(end 79.853536 -224.395792)
		(width 0.18288)
		(layer "In4.Cu")
		(net "M_B_CPU1_SB_DQ<25>")
	)
	(segment
		(start 55.946802 -202.950826)
		(end 55.540402 -202.544426)
		(width 0.18288)
		(layer "In4.Cu")
		(net "M_B_CPU1_SB_DQ<25>")
	)
	(segment
		(start 56.504586 -202.950826)
		(end 55.946802 -202.950826)
		(width 0.18288)
		(layer "In4.Cu")
		(net "M_B_CPU1_SB_DQ<25>")
	)
	(segment
		(start 48.263302 -203.338684)
		(end 48.263302 -203.02474)
		(width 0.18288)
		(layer "In4.Cu")
		(net "M_B_CPU1_SB_DQ<25>")
	)
	(segment
		(start 85.325712 -226.017328)
		(end 84.411566 -226.017328)
		(width 0.088646)
		(layer "In4.Cu")
		(net "M_B_CPU1_SB_DQ<25>")
	)
	(segment
		(start 65.000886 -203.535026)
		(end 64.47409 -203.00823)
		(width 0.18288)
		(layer "In4.Cu")
		(net "M_B_CPU1_SB_DQ<25>")
	)
	(segment
		(start 47.389542 -202.84186)
		(end 46.964346 -202.416664)
		(width 0.18288)
		(layer "In4.Cu")
		(net "M_B_CPU1_SB_DQ<25>")
	)
	(segment
		(start 58.241438 -201.91222)
		(end 57.967626 -202.186032)
		(width 0.18288)
		(layer "In4.Cu")
		(net "M_B_CPU1_SB_DQ<25>")
	)
	(segment
		(start 63.053468 -202.098148)
		(end 59.535822 -202.098148)
		(width 0.18288)
		(layer "In4.Cu")
		(net "M_B_CPU1_SB_DQ<25>")
	)
	(segment
		(start 83.72602 -225.331782)
		(end 83.72602 -225.133662)
		(width 0.088646)
		(layer "In4.Cu")
		(net "M_B_CPU1_SB_DQ<25>")
	)
	(segment
		(start 69.574918 -206.342742)
		(end 66.767202 -203.535026)
		(width 0.18288)
		(layer "In4.Cu")
		(net "M_B_CPU1_SB_DQ<25>")
	)
	(segment
		(start 50.518822 -202.84186)
		(end 50.335942 -203.02474)
		(width 0.18288)
		(layer "In4.Cu")
		(net "M_B_CPU1_SB_DQ<25>")
	)
	(segment
		(start 50.335942 -203.338684)
		(end 50.153062 -203.521564)
		(width 0.18288)
		(layer "In4.Cu")
		(net "M_B_CPU1_SB_DQ<25>")
	)
	(segment
		(start 48.954182 -203.02474)
		(end 48.954182 -203.338684)
		(width 0.18288)
		(layer "In4.Cu")
		(net "M_B_CPU1_SB_DQ<25>")
	)
	(segment
		(start 55.540402 -202.544426)
		(end 53.426106 -202.544426)
		(width 0.18288)
		(layer "In4.Cu")
		(net "M_B_CPU1_SB_DQ<25>")
	)
	(segment
		(start 48.954182 -203.338684)
		(end 48.771302 -203.521564)
		(width 0.18288)
		(layer "In4.Cu")
		(net "M_B_CPU1_SB_DQ<25>")
	)
	(segment
		(start 59.535822 -202.098148)
		(end 59.349894 -201.91222)
		(width 0.18288)
		(layer "In4.Cu")
		(net "M_B_CPU1_SB_DQ<25>")
	)
	(segment
		(start 44.490386 -204.116686)
		(end 44.065444 -203.691744)
		(width 0.20066)
		(layer "F.Cu")
		(net "M_B_CPU1_SB_DQ<24>")
	)
	(segment
		(start 39.888668 -204.355446)
		(end 39.649908 -204.116686)
		(width 0.20066)
		(layer "F.Cu")
		(net "M_B_CPU1_SB_DQ<24>")
	)
	(segment
		(start 41.299638 -203.691744)
		(end 41.29151 -203.683616)
		(width 0.101854)
		(layer "F.Cu")
		(net "M_B_CPU1_SB_DQ<24>")
	)
	(segment
		(start 40.520112 -204.182726)
		(end 40.347392 -204.355446)
		(width 0.20066)
		(layer "F.Cu")
		(net "M_B_CPU1_SB_DQ<24>")
	)
	(segment
		(start 41.547542 -203.691744)
		(end 41.299638 -203.691744)
		(width 0.101854)
		(layer "F.Cu")
		(net "M_B_CPU1_SB_DQ<24>")
	)
	(segment
		(start 40.347392 -204.355446)
		(end 39.888668 -204.355446)
		(width 0.20066)
		(layer "F.Cu")
		(net "M_B_CPU1_SB_DQ<24>")
	)
	(segment
		(start 39.649908 -204.116686)
		(end 38.315646 -204.116686)
		(width 0.20066)
		(layer "F.Cu")
		(net "M_B_CPU1_SB_DQ<24>")
	)
	(segment
		(start 44.065444 -203.691744)
		(end 43.616626 -203.691744)
		(width 0.20066)
		(layer "F.Cu")
		(net "M_B_CPU1_SB_DQ<24>")
	)
	(segment
		(start 45.859446 -204.116686)
		(end 44.490386 -204.116686)
		(width 0.20066)
		(layer "F.Cu")
		(net "M_B_CPU1_SB_DQ<24>")
	)
	(segment
		(start 40.520112 -203.893166)
		(end 40.520112 -204.182726)
		(width 0.20066)
		(layer "F.Cu")
		(net "M_B_CPU1_SB_DQ<24>")
	)
	(segment
		(start 40.729662 -203.683616)
		(end 40.520112 -203.893166)
		(width 0.20066)
		(layer "F.Cu")
		(net "M_B_CPU1_SB_DQ<24>")
	)
	(segment
		(start 85.795866 -227.367084)
		(end 85.795866 -226.831144)
		(width 0.20066)
		(layer "F.Cu")
		(net "M_B_CPU1_SB_DQ<24>")
	)
	(segment
		(start 41.29151 -203.683616)
		(end 40.729662 -203.683616)
		(width 0.20066)
		(layer "F.Cu")
		(net "M_B_CPU1_SB_DQ<24>")
	)
	(segment
		(start 43.616626 -203.691744)
		(end 41.547542 -203.691744)
		(width 0.1016)
		(layer "F.Cu")
		(net "M_B_CPU1_SB_DQ<24>")
	)
	(segment
		(start 46.964346 -204.116686)
		(end 45.859446 -204.116686)
		(width 0.20066)
		(layer "F.Cu")
		(net "M_B_CPU1_SB_DQ<24>")
	)
	(segment
		(start 48.776382 -205.297024)
		(end 48.451262 -205.297024)
		(width 0.18288)
		(layer "In4.Cu")
		(net "M_B_CPU1_SB_DQ<24>")
	)
	(segment
		(start 63.767716 -205.262226)
		(end 62.96152 -204.45603)
		(width 0.18288)
		(layer "In4.Cu")
		(net "M_B_CPU1_SB_DQ<24>")
	)
	(segment
		(start 65.928494 -205.259686)
		(end 65.925954 -205.262226)
		(width 0.18288)
		(layer "In4.Cu")
		(net "M_B_CPU1_SB_DQ<24>")
	)
	(segment
		(start 51.279806 -203.689204)
		(end 50.851562 -203.689204)
		(width 0.18288)
		(layer "In4.Cu")
		(net "M_B_CPU1_SB_DQ<24>")
	)
	(segment
		(start 59.359292 -204.152246)
		(end 59.199272 -204.312266)
		(width 0.18288)
		(layer "In4.Cu")
		(net "M_B_CPU1_SB_DQ<24>")
	)
	(segment
		(start 85.053424 -226.512882)
		(end 85.04301 -226.506786)
		(width 0.088646)
		(layer "In4.Cu")
		(net "M_B_CPU1_SB_DQ<24>")
	)
	(segment
		(start 48.451262 -205.297024)
		(end 48.268382 -205.114144)
		(width 0.18288)
		(layer "In4.Cu")
		(net "M_B_CPU1_SB_DQ<24>")
	)
	(segment
		(start 60.402216 -204.45603)
		(end 60.098432 -204.152246)
		(width 0.18288)
		(layer "In4.Cu")
		(net "M_B_CPU1_SB_DQ<24>")
	)
	(segment
		(start 85.795866 -226.831144)
		(end 86.10854 -226.831144)
		(width 0.088646)
		(layer "In4.Cu")
		(net "M_B_CPU1_SB_DQ<24>")
	)
	(segment
		(start 83.03006 -225.391472)
		(end 82.708496 -225.391472)
		(width 0.088646)
		(layer "In4.Cu")
		(net "M_B_CPU1_SB_DQ<24>")
	)
	(segment
		(start 59.039252 -204.754226)
		(end 55.99811 -204.754226)
		(width 0.18288)
		(layer "In4.Cu")
		(net "M_B_CPU1_SB_DQ<24>")
	)
	(segment
		(start 62.96152 -204.45603)
		(end 60.402216 -204.45603)
		(width 0.18288)
		(layer "In4.Cu")
		(net "M_B_CPU1_SB_DQ<24>")
	)
	(segment
		(start 79.3623 -225.391472)
		(end 74.28357 -220.312742)
		(width 0.18288)
		(layer "In4.Cu")
		(net "M_B_CPU1_SB_DQ<24>")
	)
	(segment
		(start 53.76799 -204.358494)
		(end 53.457856 -204.668628)
		(width 0.18288)
		(layer "In4.Cu")
		(net "M_B_CPU1_SB_DQ<24>")
	)
	(segment
		(start 86.10854 -226.831144)
		(end 86.16569 -226.773994)
		(width 0.088646)
		(layer "In4.Cu")
		(net "M_B_CPU1_SB_DQ<24>")
	)
	(segment
		(start 48.959262 -204.729842)
		(end 48.959262 -205.114144)
		(width 0.18288)
		(layer "In4.Cu")
		(net "M_B_CPU1_SB_DQ<24>")
	)
	(segment
		(start 68.977764 -207.503776)
		(end 66.733674 -205.259686)
		(width 0.18288)
		(layer "In4.Cu")
		(net "M_B_CPU1_SB_DQ<24>")
	)
	(segment
		(start 48.959262 -205.114144)
		(end 48.776382 -205.297024)
		(width 0.18288)
		(layer "In4.Cu")
		(net "M_B_CPU1_SB_DQ<24>")
	)
	(segment
		(start 48.268382 -204.729842)
		(end 48.085502 -204.546962)
		(width 0.18288)
		(layer "In4.Cu")
		(net "M_B_CPU1_SB_DQ<24>")
	)
	(segment
		(start 55.602378 -204.358494)
		(end 53.76799 -204.358494)
		(width 0.18288)
		(layer "In4.Cu")
		(net "M_B_CPU1_SB_DQ<24>")
	)
	(segment
		(start 74.28357 -220.312742)
		(end 68.977764 -207.503776)
		(width 0.18288)
		(layer "In4.Cu")
		(net "M_B_CPU1_SB_DQ<24>")
	)
	(segment
		(start 53.07457 -204.668628)
		(end 52.764436 -204.358494)
		(width 0.18288)
		(layer "In4.Cu")
		(net "M_B_CPU1_SB_DQ<24>")
	)
	(segment
		(start 47.394622 -204.546962)
		(end 46.964346 -204.116686)
		(width 0.18288)
		(layer "In4.Cu")
		(net "M_B_CPU1_SB_DQ<24>")
	)
	(segment
		(start 82.708496 -225.391472)
		(end 79.3623 -225.391472)
		(width 0.18288)
		(layer "In4.Cu")
		(net "M_B_CPU1_SB_DQ<24>")
	)
	(segment
		(start 59.199272 -204.594206)
		(end 59.039252 -204.754226)
		(width 0.18288)
		(layer "In4.Cu")
		(net "M_B_CPU1_SB_DQ<24>")
	)
	(segment
		(start 50.851562 -203.689204)
		(end 50.153316 -204.38745)
		(width 0.18288)
		(layer "In4.Cu")
		(net "M_B_CPU1_SB_DQ<24>")
	)
	(segment
		(start 51.949096 -204.358494)
		(end 51.279806 -203.689204)
		(width 0.18288)
		(layer "In4.Cu")
		(net "M_B_CPU1_SB_DQ<24>")
	)
	(segment
		(start 50.153316 -204.38745)
		(end 49.301654 -204.38745)
		(width 0.18288)
		(layer "In4.Cu")
		(net "M_B_CPU1_SB_DQ<24>")
	)
	(segment
		(start 48.268382 -205.114144)
		(end 48.268382 -204.729842)
		(width 0.18288)
		(layer "In4.Cu")
		(net "M_B_CPU1_SB_DQ<24>")
	)
	(segment
		(start 84.571078 -226.521772)
		(end 84.16036 -226.521772)
		(width 0.088646)
		(layer "In4.Cu")
		(net "M_B_CPU1_SB_DQ<24>")
	)
	(segment
		(start 49.301654 -204.38745)
		(end 48.959262 -204.729842)
		(width 0.18288)
		(layer "In4.Cu")
		(net "M_B_CPU1_SB_DQ<24>")
	)
	(segment
		(start 59.199272 -204.312266)
		(end 59.199272 -204.594206)
		(width 0.18288)
		(layer "In4.Cu")
		(net "M_B_CPU1_SB_DQ<24>")
	)
	(segment
		(start 48.085502 -204.546962)
		(end 47.394622 -204.546962)
		(width 0.18288)
		(layer "In4.Cu")
		(net "M_B_CPU1_SB_DQ<24>")
	)
	(segment
		(start 60.098432 -204.152246)
		(end 59.359292 -204.152246)
		(width 0.18288)
		(layer "In4.Cu")
		(net "M_B_CPU1_SB_DQ<24>")
	)
	(segment
		(start 55.99811 -204.754226)
		(end 55.602378 -204.358494)
		(width 0.18288)
		(layer "In4.Cu")
		(net "M_B_CPU1_SB_DQ<24>")
	)
	(segment
		(start 84.16036 -226.521772)
		(end 83.03006 -225.391472)
		(width 0.088646)
		(layer "In4.Cu")
		(net "M_B_CPU1_SB_DQ<24>")
	)
	(segment
		(start 53.457856 -204.668628)
		(end 53.07457 -204.668628)
		(width 0.18288)
		(layer "In4.Cu")
		(net "M_B_CPU1_SB_DQ<24>")
	)
	(segment
		(start 65.925954 -205.262226)
		(end 63.767716 -205.262226)
		(width 0.18288)
		(layer "In4.Cu")
		(net "M_B_CPU1_SB_DQ<24>")
	)
	(segment
		(start 66.733674 -205.259686)
		(end 65.928494 -205.259686)
		(width 0.18288)
		(layer "In4.Cu")
		(net "M_B_CPU1_SB_DQ<24>")
	)
	(segment
		(start 52.764436 -204.358494)
		(end 51.949096 -204.358494)
		(width 0.18288)
		(layer "In4.Cu")
		(net "M_B_CPU1_SB_DQ<24>")
	)
	(arc
		(start 85.983064 -226.506786)
		(mid 85.795866 -226.456643)
		(end 85.608668 -226.506786)
		(width 0.088646)
		(layer "In4.Cu")
		(net "M_B_CPU1_SB_DQ<24>")
	)
	(arc
		(start 86.16569 -226.773994)
		(mid 86.104747 -226.619631)
		(end 85.983064 -226.506786)
		(width 0.088646)
		(layer "In4.Cu")
		(net "M_B_CPU1_SB_DQ<24>")
	)
	(arc
		(start 85.04301 -226.506786)
		(mid 84.869363 -226.456736)
		(end 84.69249 -226.493832)
		(width 0.088646)
		(layer "In4.Cu")
		(net "M_B_CPU1_SB_DQ<24>")
	)
	(arc
		(start 84.69249 -226.493832)
		(mid 84.633367 -226.51467)
		(end 84.571078 -226.521772)
		(width 0.088646)
		(layer "In4.Cu")
		(net "M_B_CPU1_SB_DQ<24>")
	)
	(arc
		(start 85.608668 -226.506786)
		(mid 85.331855 -226.582656)
		(end 85.053424 -226.512882)
		(width 0.088646)
		(layer "In4.Cu")
		(net "M_B_CPU1_SB_DQ<24>")
	)
	(segment
		(start 44.112942 -204.96657)
		(end 42.415714 -204.96657)
		(width 0.20066)
		(layer "F.Cu")
		(net "M_B_CPU1_SB_DQ<23>")
	)
	(segment
		(start 44.38142 -205.405736)
		(end 44.238926 -205.263242)
		(width 0.20066)
		(layer "F.Cu")
		(net "M_B_CPU1_SB_DQ<23>")
	)
	(segment
		(start 48.489362 -205.174088)
		(end 48.277526 -204.962252)
		(width 0.20066)
		(layer "F.Cu")
		(net "M_B_CPU1_SB_DQ<23>")
	)
	(segment
		(start 49.143412 -204.96657)
		(end 48.935894 -205.174088)
		(width 0.20066)
		(layer "F.Cu")
		(net "M_B_CPU1_SB_DQ<23>")
	)
	(segment
		(start 44.987464 -205.391512)
		(end 44.749466 -205.391512)
		(width 0.101854)
		(layer "F.Cu")
		(net "M_B_CPU1_SB_DQ<23>")
	)
	(segment
		(start 90.024966 -226.553014)
		(end 90.024966 -226.017328)
		(width 0.20066)
		(layer "F.Cu")
		(net "M_B_CPU1_SB_DQ<23>")
	)
	(segment
		(start 49.959514 -204.96657)
		(end 49.143412 -204.96657)
		(width 0.20066)
		(layer "F.Cu")
		(net "M_B_CPU1_SB_DQ<23>")
	)
	(segment
		(start 47.060358 -205.391512)
		(end 44.987464 -205.391512)
		(width 0.1016)
		(layer "F.Cu")
		(net "M_B_CPU1_SB_DQ<23>")
	)
	(segment
		(start 44.238926 -205.263242)
		(end 44.238926 -205.092554)
		(width 0.20066)
		(layer "F.Cu")
		(net "M_B_CPU1_SB_DQ<23>")
	)
	(segment
		(start 48.935894 -205.174088)
		(end 48.489362 -205.174088)
		(width 0.20066)
		(layer "F.Cu")
		(net "M_B_CPU1_SB_DQ<23>")
	)
	(segment
		(start 47.753778 -205.242414)
		(end 47.60468 -205.391512)
		(width 0.20066)
		(layer "F.Cu")
		(net "M_B_CPU1_SB_DQ<23>")
	)
	(segment
		(start 44.238926 -205.092554)
		(end 44.112942 -204.96657)
		(width 0.20066)
		(layer "F.Cu")
		(net "M_B_CPU1_SB_DQ<23>")
	)
	(segment
		(start 90.024712 -226.553268)
		(end 90.024966 -226.553014)
		(width 0.20066)
		(layer "F.Cu")
		(net "M_B_CPU1_SB_DQ<23>")
	)
	(segment
		(start 47.882302 -204.962252)
		(end 47.753778 -205.090776)
		(width 0.20066)
		(layer "F.Cu")
		(net "M_B_CPU1_SB_DQ<23>")
	)
	(segment
		(start 47.60468 -205.391512)
		(end 47.060358 -205.391512)
		(width 0.20066)
		(layer "F.Cu")
		(net "M_B_CPU1_SB_DQ<23>")
	)
	(segment
		(start 51.064414 -204.96657)
		(end 49.959514 -204.96657)
		(width 0.20066)
		(layer "F.Cu")
		(net "M_B_CPU1_SB_DQ<23>")
	)
	(segment
		(start 48.277526 -204.962252)
		(end 47.882302 -204.962252)
		(width 0.20066)
		(layer "F.Cu")
		(net "M_B_CPU1_SB_DQ<23>")
	)
	(segment
		(start 44.749466 -205.391512)
		(end 44.735242 -205.405736)
		(width 0.101854)
		(layer "F.Cu")
		(net "M_B_CPU1_SB_DQ<23>")
	)
	(segment
		(start 47.753778 -205.090776)
		(end 47.753778 -205.242414)
		(width 0.20066)
		(layer "F.Cu")
		(net "M_B_CPU1_SB_DQ<23>")
	)
	(segment
		(start 44.735242 -205.405736)
		(end 44.38142 -205.405736)
		(width 0.20066)
		(layer "F.Cu")
		(net "M_B_CPU1_SB_DQ<23>")
	)
	(segment
		(start 54.840632 -204.444092)
		(end 54.732682 -204.336142)
		(width 0.18288)
		(layer "In2.Cu")
		(net "M_B_CPU1_SB_DQ<23>")
	)
	(segment
		(start 65.960244 -203.670408)
		(end 65.70345 -203.927202)
		(width 0.18288)
		(layer "In2.Cu")
		(net "M_B_CPU1_SB_DQ<23>")
	)
	(segment
		(start 89.650316 -224.389442)
		(end 89.650316 -224.379536)
		(width 0.088646)
		(layer "In2.Cu")
		(net "M_B_CPU1_SB_DQ<23>")
	)
	(segment
		(start 86.237826 -220.380306)
		(end 85.763354 -219.905834)
		(width 0.18288)
		(layer "In2.Cu")
		(net "M_B_CPU1_SB_DQ<23>")
	)
	(segment
		(start 68.288662 -203.882752)
		(end 68.288662 -204.71003)
		(width 0.18288)
		(layer "In2.Cu")
		(net "M_B_CPU1_SB_DQ<23>")
	)
	(segment
		(start 65.70345 -203.927202)
		(end 64.478154 -203.927202)
		(width 0.18288)
		(layer "In2.Cu")
		(net "M_B_CPU1_SB_DQ<23>")
	)
	(segment
		(start 69.093588 -204.71003)
		(end 69.093588 -203.882498)
		(width 0.18288)
		(layer "In2.Cu")
		(net "M_B_CPU1_SB_DQ<23>")
	)
	(segment
		(start 64.478154 -203.927202)
		(end 64.110362 -203.55941)
		(width 0.18288)
		(layer "In2.Cu")
		(net "M_B_CPU1_SB_DQ<23>")
	)
	(segment
		(start 67.192144 -203.670408)
		(end 65.960244 -203.670408)
		(width 0.18288)
		(layer "In2.Cu")
		(net "M_B_CPU1_SB_DQ<23>")
	)
	(segment
		(start 55.521352 -203.686664)
		(end 55.328312 -203.879704)
		(width 0.18288)
		(layer "In2.Cu")
		(net "M_B_CPU1_SB_DQ<23>")
	)
	(segment
		(start 87.117174 -221.530672)
		(end 86.770464 -221.183962)
		(width 0.088646)
		(layer "In2.Cu")
		(net "M_B_CPU1_SB_DQ<23>")
	)
	(segment
		(start 69.093588 -203.882498)
		(end 68.900548 -203.689458)
		(width 0.18288)
		(layer "In2.Cu")
		(net "M_B_CPU1_SB_DQ<23>")
	)
	(segment
		(start 64.110362 -203.55941)
		(end 63.641478 -203.55941)
		(width 0.18288)
		(layer "In2.Cu")
		(net "M_B_CPU1_SB_DQ<23>")
	)
	(segment
		(start 87.50046 -222.27921)
		(end 87.496904 -222.276924)
		(width 0.088646)
		(layer "In2.Cu")
		(net "M_B_CPU1_SB_DQ<23>")
	)
	(segment
		(start 90.024966 -226.017328)
		(end 89.712292 -226.017328)
		(width 0.088646)
		(layer "In2.Cu")
		(net "M_B_CPU1_SB_DQ<23>")
	)
	(segment
		(start 59.138566 -203.99121)
		(end 58.83402 -203.686664)
		(width 0.18288)
		(layer "In2.Cu")
		(net "M_B_CPU1_SB_DQ<23>")
	)
	(segment
		(start 63.304166 -204.15123)
		(end 62.854078 -204.15123)
		(width 0.18288)
		(layer "In2.Cu")
		(net "M_B_CPU1_SB_DQ<23>")
	)
	(segment
		(start 89.828878 -225.69805)
		(end 89.837768 -225.69297)
		(width 0.088646)
		(layer "In2.Cu")
		(net "M_B_CPU1_SB_DQ<23>")
	)
	(segment
		(start 63.478918 -203.72197)
		(end 63.478918 -203.976478)
		(width 0.18288)
		(layer "In2.Cu")
		(net "M_B_CPU1_SB_DQ<23>")
	)
	(segment
		(start 62.607698 -203.90485)
		(end 62.04204 -203.90485)
		(width 0.18288)
		(layer "In2.Cu")
		(net "M_B_CPU1_SB_DQ<23>")
	)
	(segment
		(start 68.900548 -203.689458)
		(end 68.481956 -203.689458)
		(width 0.18288)
		(layer "In2.Cu")
		(net "M_B_CPU1_SB_DQ<23>")
	)
	(segment
		(start 55.328312 -204.229462)
		(end 55.113682 -204.444092)
		(width 0.18288)
		(layer "In2.Cu")
		(net "M_B_CPU1_SB_DQ<23>")
	)
	(segment
		(start 54.732682 -204.336142)
		(end 54.459632 -204.336142)
		(width 0.18288)
		(layer "In2.Cu")
		(net "M_B_CPU1_SB_DQ<23>")
	)
	(segment
		(start 67.385184 -203.863448)
		(end 67.192144 -203.670408)
		(width 0.18288)
		(layer "In2.Cu")
		(net "M_B_CPU1_SB_DQ<23>")
	)
	(segment
		(start 69.286628 -204.90307)
		(end 69.093588 -204.71003)
		(width 0.18288)
		(layer "In2.Cu")
		(net "M_B_CPU1_SB_DQ<23>")
	)
	(segment
		(start 85.029294 -219.905834)
		(end 70.02653 -204.90307)
		(width 0.18288)
		(layer "In2.Cu")
		(net "M_B_CPU1_SB_DQ<23>")
	)
	(segment
		(start 55.113682 -204.444092)
		(end 54.840632 -204.444092)
		(width 0.18288)
		(layer "In2.Cu")
		(net "M_B_CPU1_SB_DQ<23>")
	)
	(segment
		(start 62.04204 -203.90485)
		(end 61.695838 -203.558648)
		(width 0.18288)
		(layer "In2.Cu")
		(net "M_B_CPU1_SB_DQ<23>")
	)
	(segment
		(start 67.385184 -204.71003)
		(end 67.385184 -203.863448)
		(width 0.18288)
		(layer "In2.Cu")
		(net "M_B_CPU1_SB_DQ<23>")
	)
	(segment
		(start 87.300816 -221.94774)
		(end 87.300816 -221.937834)
		(width 0.088646)
		(layer "In2.Cu")
		(net "M_B_CPU1_SB_DQ<23>")
	)
	(segment
		(start 85.763354 -219.905834)
		(end 85.029294 -219.905834)
		(width 0.18288)
		(layer "In2.Cu")
		(net "M_B_CPU1_SB_DQ<23>")
	)
	(segment
		(start 68.481956 -203.689458)
		(end 68.288662 -203.882752)
		(width 0.18288)
		(layer "In2.Cu")
		(net "M_B_CPU1_SB_DQ<23>")
	)
	(segment
		(start 68.095622 -204.90307)
		(end 67.578224 -204.90307)
		(width 0.18288)
		(layer "In2.Cu")
		(net "M_B_CPU1_SB_DQ<23>")
	)
	(segment
		(start 86.770464 -220.912944)
		(end 86.237826 -220.380306)
		(width 0.088646)
		(layer "In2.Cu")
		(net "M_B_CPU1_SB_DQ<23>")
	)
	(segment
		(start 51.505612 -204.525372)
		(end 51.064414 -204.96657)
		(width 0.18288)
		(layer "In2.Cu")
		(net "M_B_CPU1_SB_DQ<23>")
	)
	(segment
		(start 89.712292 -226.017328)
		(end 89.654888 -225.959924)
		(width 0.088646)
		(layer "In2.Cu")
		(net "M_B_CPU1_SB_DQ<23>")
	)
	(segment
		(start 63.641478 -203.55941)
		(end 63.478918 -203.72197)
		(width 0.18288)
		(layer "In2.Cu")
		(net "M_B_CPU1_SB_DQ<23>")
	)
	(segment
		(start 88.332564 -223.085914)
		(end 88.324182 -223.09074)
		(width 0.088646)
		(layer "In2.Cu")
		(net "M_B_CPU1_SB_DQ<23>")
	)
	(segment
		(start 55.328312 -203.879704)
		(end 55.328312 -204.229462)
		(width 0.18288)
		(layer "In2.Cu")
		(net "M_B_CPU1_SB_DQ<23>")
	)
	(segment
		(start 87.488268 -222.272098)
		(end 87.479378 -222.267018)
		(width 0.088646)
		(layer "In2.Cu")
		(net "M_B_CPU1_SB_DQ<23>")
	)
	(segment
		(start 62.854078 -204.15123)
		(end 62.607698 -203.90485)
		(width 0.18288)
		(layer "In2.Cu")
		(net "M_B_CPU1_SB_DQ<23>")
	)
	(segment
		(start 86.770464 -221.183962)
		(end 86.770464 -220.912944)
		(width 0.088646)
		(layer "In2.Cu")
		(net "M_B_CPU1_SB_DQ<23>")
	)
	(segment
		(start 70.02653 -204.90307)
		(end 69.286628 -204.90307)
		(width 0.18288)
		(layer "In2.Cu")
		(net "M_B_CPU1_SB_DQ<23>")
	)
	(segment
		(start 54.459632 -204.336142)
		(end 54.270402 -204.525372)
		(width 0.18288)
		(layer "In2.Cu")
		(net "M_B_CPU1_SB_DQ<23>")
	)
	(segment
		(start 88.347296 -223.077278)
		(end 88.332564 -223.085914)
		(width 0.088646)
		(layer "In2.Cu")
		(net "M_B_CPU1_SB_DQ<23>")
	)
	(segment
		(start 59.765692 -203.99121)
		(end 59.138566 -203.99121)
		(width 0.18288)
		(layer "In2.Cu")
		(net "M_B_CPU1_SB_DQ<23>")
	)
	(segment
		(start 89.180416 -223.575626)
		(end 89.180416 -223.561402)
		(width 0.088646)
		(layer "In2.Cu")
		(net "M_B_CPU1_SB_DQ<23>")
	)
	(segment
		(start 61.695838 -203.558648)
		(end 60.198254 -203.558648)
		(width 0.18288)
		(layer "In2.Cu")
		(net "M_B_CPU1_SB_DQ<23>")
	)
	(segment
		(start 89.837768 -224.7138)
		(end 89.828878 -224.70872)
		(width 0.088646)
		(layer "In2.Cu")
		(net "M_B_CPU1_SB_DQ<23>")
	)
	(segment
		(start 60.198254 -203.558648)
		(end 59.765692 -203.99121)
		(width 0.18288)
		(layer "In2.Cu")
		(net "M_B_CPU1_SB_DQ<23>")
	)
	(segment
		(start 90.119962 -225.225356)
		(end 90.119962 -225.187764)
		(width 0.088646)
		(layer "In2.Cu")
		(net "M_B_CPU1_SB_DQ<23>")
	)
	(segment
		(start 54.270402 -204.525372)
		(end 51.505612 -204.525372)
		(width 0.18288)
		(layer "In2.Cu")
		(net "M_B_CPU1_SB_DQ<23>")
	)
	(segment
		(start 58.83402 -203.686664)
		(end 55.521352 -203.686664)
		(width 0.18288)
		(layer "In2.Cu")
		(net "M_B_CPU1_SB_DQ<23>")
	)
	(segment
		(start 87.958422 -223.085914)
		(end 87.949532 -223.080834)
		(width 0.088646)
		(layer "In2.Cu")
		(net "M_B_CPU1_SB_DQ<23>")
	)
	(segment
		(start 89.367868 -223.899984)
		(end 89.358978 -223.894904)
		(width 0.088646)
		(layer "In2.Cu")
		(net "M_B_CPU1_SB_DQ<23>")
	)
	(segment
		(start 63.478918 -203.976478)
		(end 63.304166 -204.15123)
		(width 0.18288)
		(layer "In2.Cu")
		(net "M_B_CPU1_SB_DQ<23>")
	)
	(segment
		(start 67.578224 -204.90307)
		(end 67.385184 -204.71003)
		(width 0.18288)
		(layer "In2.Cu")
		(net "M_B_CPU1_SB_DQ<23>")
	)
	(segment
		(start 87.496904 -222.276924)
		(end 87.488268 -222.272098)
		(width 0.088646)
		(layer "In2.Cu")
		(net "M_B_CPU1_SB_DQ<23>")
	)
	(segment
		(start 68.288662 -204.71003)
		(end 68.095622 -204.90307)
		(width 0.18288)
		(layer "In2.Cu")
		(net "M_B_CPU1_SB_DQ<23>")
	)
	(arc
		(start 90.119962 -225.187764)
		(mid 90.040592 -224.91403)
		(end 89.837768 -224.7138)
		(width 0.088646)
		(layer "In2.Cu")
		(net "M_B_CPU1_SB_DQ<23>")
	)
	(arc
		(start 87.479378 -222.267018)
		(mid 87.348464 -222.130658)
		(end 87.300816 -221.94774)
		(width 0.088646)
		(layer "In2.Cu")
		(net "M_B_CPU1_SB_DQ<23>")
	)
	(arc
		(start 89.828878 -224.70872)
		(mid 89.697964 -224.57236)
		(end 89.650316 -224.389442)
		(width 0.088646)
		(layer "In2.Cu")
		(net "M_B_CPU1_SB_DQ<23>")
	)
	(arc
		(start 87.77097 -222.761556)
		(mid 87.698735 -222.485032)
		(end 87.50046 -222.27921)
		(width 0.088646)
		(layer "In2.Cu")
		(net "M_B_CPU1_SB_DQ<23>")
	)
	(arc
		(start 89.650316 -224.379536)
		(mid 89.572205 -224.102587)
		(end 89.367868 -223.899984)
		(width 0.088646)
		(layer "In2.Cu")
		(net "M_B_CPU1_SB_DQ<23>")
	)
	(arc
		(start 89.180416 -223.561402)
		(mid 89.101275 -223.286779)
		(end 88.897968 -223.085914)
		(width 0.088646)
		(layer "In2.Cu")
		(net "M_B_CPU1_SB_DQ<23>")
	)
	(arc
		(start 89.837768 -225.69297)
		(mid 90.03905 -225.495483)
		(end 90.119962 -225.225356)
		(width 0.088646)
		(layer "In2.Cu")
		(net "M_B_CPU1_SB_DQ<23>")
	)
	(arc
		(start 87.300816 -221.937834)
		(mid 87.250918 -221.715344)
		(end 87.117174 -221.530672)
		(width 0.088646)
		(layer "In2.Cu")
		(net "M_B_CPU1_SB_DQ<23>")
	)
	(arc
		(start 89.654888 -225.959924)
		(mid 89.713044 -225.809811)
		(end 89.828878 -225.69805)
		(width 0.088646)
		(layer "In2.Cu")
		(net "M_B_CPU1_SB_DQ<23>")
	)
	(arc
		(start 88.324182 -223.09074)
		(mid 88.140674 -223.136018)
		(end 87.958422 -223.085914)
		(width 0.088646)
		(layer "In2.Cu")
		(net "M_B_CPU1_SB_DQ<23>")
	)
	(arc
		(start 88.897968 -223.085914)
		(mid 88.623739 -223.009989)
		(end 88.347296 -223.077278)
		(width 0.088646)
		(layer "In2.Cu")
		(net "M_B_CPU1_SB_DQ<23>")
	)
	(arc
		(start 87.949532 -223.080834)
		(mid 87.818618 -222.944474)
		(end 87.77097 -222.761556)
		(width 0.088646)
		(layer "In2.Cu")
		(net "M_B_CPU1_SB_DQ<23>")
	)
	(arc
		(start 89.358978 -223.894904)
		(mid 89.228064 -223.758544)
		(end 89.180416 -223.575626)
		(width 0.088646)
		(layer "In2.Cu")
		(net "M_B_CPU1_SB_DQ<23>")
	)
	(segment
		(start 48.432974 -206.878428)
		(end 48.004476 -206.878428)
		(width 0.20066)
		(layer "F.Cu")
		(net "M_B_CPU1_SB_DQ<22>")
	)
	(segment
		(start 44.735242 -206.23149)
		(end 43.99788 -206.23149)
		(width 0.20066)
		(layer "F.Cu")
		(net "M_B_CPU1_SB_DQ<22>")
	)
	(segment
		(start 51.064414 -206.666592)
		(end 49.959514 -206.666592)
		(width 0.20066)
		(layer "F.Cu")
		(net "M_B_CPU1_SB_DQ<22>")
	)
	(segment
		(start 45.000418 -206.24165)
		(end 44.745402 -206.24165)
		(width 0.101854)
		(layer "F.Cu")
		(net "M_B_CPU1_SB_DQ<22>")
	)
	(segment
		(start 47.693326 -206.24165)
		(end 47.060358 -206.24165)
		(width 0.20066)
		(layer "F.Cu")
		(net "M_B_CPU1_SB_DQ<22>")
	)
	(segment
		(start 44.745402 -206.24165)
		(end 44.735242 -206.23149)
		(width 0.101854)
		(layer "F.Cu")
		(net "M_B_CPU1_SB_DQ<22>")
	)
	(segment
		(start 43.562778 -206.666592)
		(end 42.415714 -206.666592)
		(width 0.20066)
		(layer "F.Cu")
		(net "M_B_CPU1_SB_DQ<22>")
	)
	(segment
		(start 47.83709 -206.711042)
		(end 47.83709 -206.385414)
		(width 0.20066)
		(layer "F.Cu")
		(net "M_B_CPU1_SB_DQ<22>")
	)
	(segment
		(start 49.959514 -206.666592)
		(end 48.64481 -206.666592)
		(width 0.20066)
		(layer "F.Cu")
		(net "M_B_CPU1_SB_DQ<22>")
	)
	(segment
		(start 43.99788 -206.23149)
		(end 43.562778 -206.666592)
		(width 0.20066)
		(layer "F.Cu")
		(net "M_B_CPU1_SB_DQ<22>")
	)
	(segment
		(start 47.060358 -206.24165)
		(end 45.000418 -206.24165)
		(width 0.1016)
		(layer "F.Cu")
		(net "M_B_CPU1_SB_DQ<22>")
	)
	(segment
		(start 90.494612 -227.36683)
		(end 90.494612 -226.831144)
		(width 0.20066)
		(layer "F.Cu")
		(net "M_B_CPU1_SB_DQ<22>")
	)
	(segment
		(start 48.004476 -206.878428)
		(end 47.83709 -206.711042)
		(width 0.20066)
		(layer "F.Cu")
		(net "M_B_CPU1_SB_DQ<22>")
	)
	(segment
		(start 47.83709 -206.385414)
		(end 47.693326 -206.24165)
		(width 0.20066)
		(layer "F.Cu")
		(net "M_B_CPU1_SB_DQ<22>")
	)
	(segment
		(start 90.494866 -227.367084)
		(end 90.494612 -227.36683)
		(width 0.20066)
		(layer "F.Cu")
		(net "M_B_CPU1_SB_DQ<22>")
	)
	(segment
		(start 48.64481 -206.666592)
		(end 48.432974 -206.878428)
		(width 0.20066)
		(layer "F.Cu")
		(net "M_B_CPU1_SB_DQ<22>")
	)
	(segment
		(start 85.37575 -220.956886)
		(end 84.556854 -220.956886)
		(width 0.18288)
		(layer "In2.Cu")
		(net "M_B_CPU1_SB_DQ<22>")
	)
	(segment
		(start 61.831474 -205.401164)
		(end 61.540136 -205.109826)
		(width 0.18288)
		(layer "In2.Cu")
		(net "M_B_CPU1_SB_DQ<22>")
	)
	(segment
		(start 86.333838 -222.075756)
		(end 86.333838 -221.914974)
		(width 0.088646)
		(layer "In2.Cu")
		(net "M_B_CPU1_SB_DQ<22>")
	)
	(segment
		(start 55.908956 -206.292704)
		(end 55.624476 -206.577184)
		(width 0.18288)
		(layer "In2.Cu")
		(net "M_B_CPU1_SB_DQ<22>")
	)
	(segment
		(start 55.624476 -206.577184)
		(end 55.351172 -206.577184)
		(width 0.18288)
		(layer "In2.Cu")
		(net "M_B_CPU1_SB_DQ<22>")
	)
	(segment
		(start 67.43446 -205.933548)
		(end 66.958972 -205.933548)
		(width 0.18288)
		(layer "In2.Cu")
		(net "M_B_CPU1_SB_DQ<22>")
	)
	(segment
		(start 68.590668 -206.915766)
		(end 67.82054 -206.915766)
		(width 0.18288)
		(layer "In2.Cu")
		(net "M_B_CPU1_SB_DQ<22>")
	)
	(segment
		(start 89.180416 -225.2218)
		(end 89.180416 -225.193352)
		(width 0.088646)
		(layer "In2.Cu")
		(net "M_B_CPU1_SB_DQ<22>")
	)
	(segment
		(start 63.97498 -205.20787)
		(end 62.60846 -205.20787)
		(width 0.18288)
		(layer "In2.Cu")
		(net "M_B_CPU1_SB_DQ<22>")
	)
	(segment
		(start 86.830916 -222.761556)
		(end 86.830916 -222.75165)
		(width 0.088646)
		(layer "In2.Cu")
		(net "M_B_CPU1_SB_DQ<22>")
	)
	(segment
		(start 65.735962 -205.517242)
		(end 64.284352 -205.517242)
		(width 0.18288)
		(layer "In2.Cu")
		(net "M_B_CPU1_SB_DQ<22>")
	)
	(segment
		(start 87.018368 -223.085914)
		(end 87.009478 -223.080834)
		(width 0.088646)
		(layer "In2.Cu")
		(net "M_B_CPU1_SB_DQ<22>")
	)
	(segment
		(start 87.488268 -223.899984)
		(end 87.479378 -223.894904)
		(width 0.088646)
		(layer "In2.Cu")
		(net "M_B_CPU1_SB_DQ<22>")
	)
	(segment
		(start 56.611774 -205.337664)
		(end 56.11495 -205.337664)
		(width 0.18288)
		(layer "In2.Cu")
		(net "M_B_CPU1_SB_DQ<22>")
	)
	(segment
		(start 58.963814 -205.19263)
		(end 58.604912 -205.19263)
		(width 0.18288)
		(layer "In2.Cu")
		(net "M_B_CPU1_SB_DQ<22>")
	)
	(segment
		(start 62.415166 -205.401164)
		(end 61.831474 -205.401164)
		(width 0.18288)
		(layer "In2.Cu")
		(net "M_B_CPU1_SB_DQ<22>")
	)
	(segment
		(start 65.9257 -205.327504)
		(end 65.735962 -205.517242)
		(width 0.18288)
		(layer "In2.Cu")
		(net "M_B_CPU1_SB_DQ<22>")
	)
	(segment
		(start 90.494612 -226.831144)
		(end 90.475308 -226.831144)
		(width 0.088646)
		(layer "In2.Cu")
		(net "M_B_CPU1_SB_DQ<22>")
	)
	(segment
		(start 86.333838 -221.914974)
		(end 85.518498 -221.099634)
		(width 0.088646)
		(layer "In2.Cu")
		(net "M_B_CPU1_SB_DQ<22>")
	)
	(segment
		(start 54.495446 -206.043022)
		(end 54.12867 -206.409798)
		(width 0.18288)
		(layer "In2.Cu")
		(net "M_B_CPU1_SB_DQ<22>")
	)
	(segment
		(start 69.726556 -206.706724)
		(end 69.726556 -206.13624)
		(width 0.18288)
		(layer "In2.Cu")
		(net "M_B_CPU1_SB_DQ<22>")
	)
	(segment
		(start 86.470744 -222.212662)
		(end 86.333838 -222.075756)
		(width 0.088646)
		(layer "In2.Cu")
		(net "M_B_CPU1_SB_DQ<22>")
	)
	(segment
		(start 84.556854 -220.956886)
		(end 70.499732 -206.899764)
		(width 0.18288)
		(layer "In2.Cu")
		(net "M_B_CPU1_SB_DQ<22>")
	)
	(segment
		(start 55.908956 -205.543658)
		(end 55.908956 -206.292704)
		(width 0.18288)
		(layer "In2.Cu")
		(net "M_B_CPU1_SB_DQ<22>")
	)
	(segment
		(start 88.897968 -226.341686)
		(end 88.889078 -226.336606)
		(width 0.088646)
		(layer "In2.Cu")
		(net "M_B_CPU1_SB_DQ<22>")
	)
	(segment
		(start 56.11495 -205.337664)
		(end 55.908956 -205.543658)
		(width 0.18288)
		(layer "In2.Cu")
		(net "M_B_CPU1_SB_DQ<22>")
	)
	(segment
		(start 88.427814 -223.899984)
		(end 88.4174 -223.893888)
		(width 0.088646)
		(layer "In2.Cu")
		(net "M_B_CPU1_SB_DQ<22>")
	)
	(segment
		(start 55.351172 -206.577184)
		(end 54.81701 -206.043022)
		(width 0.18288)
		(layer "In2.Cu")
		(net "M_B_CPU1_SB_DQ<22>")
	)
	(segment
		(start 66.958972 -205.933548)
		(end 66.352928 -205.327504)
		(width 0.18288)
		(layer "In2.Cu")
		(net "M_B_CPU1_SB_DQ<22>")
	)
	(segment
		(start 61.540136 -205.109826)
		(end 60.37072 -205.109826)
		(width 0.18288)
		(layer "In2.Cu")
		(net "M_B_CPU1_SB_DQ<22>")
	)
	(segment
		(start 70.499732 -206.899764)
		(end 69.919596 -206.899764)
		(width 0.18288)
		(layer "In2.Cu")
		(net "M_B_CPU1_SB_DQ<22>")
	)
	(segment
		(start 88.889078 -225.69805)
		(end 88.897968 -225.69297)
		(width 0.088646)
		(layer "In2.Cu")
		(net "M_B_CPU1_SB_DQ<22>")
	)
	(segment
		(start 62.60846 -205.20787)
		(end 62.415166 -205.401164)
		(width 0.18288)
		(layer "In2.Cu")
		(net "M_B_CPU1_SB_DQ<22>")
	)
	(segment
		(start 87.300816 -223.575626)
		(end 87.300816 -223.557084)
		(width 0.088646)
		(layer "In2.Cu")
		(net "M_B_CPU1_SB_DQ<22>")
	)
	(segment
		(start 58.604912 -205.19263)
		(end 58.17743 -205.620112)
		(width 0.18288)
		(layer "In2.Cu")
		(net "M_B_CPU1_SB_DQ<22>")
	)
	(segment
		(start 54.81701 -206.043022)
		(end 54.495446 -206.043022)
		(width 0.18288)
		(layer "In2.Cu")
		(net "M_B_CPU1_SB_DQ<22>")
	)
	(segment
		(start 52.449476 -206.201264)
		(end 51.529742 -206.201264)
		(width 0.18288)
		(layer "In2.Cu")
		(net "M_B_CPU1_SB_DQ<22>")
	)
	(segment
		(start 67.6275 -206.722726)
		(end 67.6275 -206.126588)
		(width 0.18288)
		(layer "In2.Cu")
		(net "M_B_CPU1_SB_DQ<22>")
	)
	(segment
		(start 68.783708 -206.13624)
		(end 68.783708 -206.722726)
		(width 0.18288)
		(layer "In2.Cu")
		(net "M_B_CPU1_SB_DQ<22>")
	)
	(segment
		(start 67.6275 -206.126588)
		(end 67.43446 -205.933548)
		(width 0.18288)
		(layer "In2.Cu")
		(net "M_B_CPU1_SB_DQ<22>")
	)
	(segment
		(start 64.284352 -205.517242)
		(end 63.97498 -205.20787)
		(width 0.18288)
		(layer "In2.Cu")
		(net "M_B_CPU1_SB_DQ<22>")
	)
	(segment
		(start 51.529742 -206.201264)
		(end 51.064414 -206.666592)
		(width 0.18288)
		(layer "In2.Cu")
		(net "M_B_CPU1_SB_DQ<22>")
	)
	(segment
		(start 66.352928 -205.327504)
		(end 65.9257 -205.327504)
		(width 0.18288)
		(layer "In2.Cu")
		(net "M_B_CPU1_SB_DQ<22>")
	)
	(segment
		(start 52.65801 -206.409798)
		(end 52.449476 -206.201264)
		(width 0.18288)
		(layer "In2.Cu")
		(net "M_B_CPU1_SB_DQ<22>")
	)
	(segment
		(start 60.37072 -205.109826)
		(end 59.954922 -205.525624)
		(width 0.18288)
		(layer "In2.Cu")
		(net "M_B_CPU1_SB_DQ<22>")
	)
	(segment
		(start 88.43391 -223.90354)
		(end 88.427814 -223.899984)
		(width 0.088646)
		(layer "In2.Cu")
		(net "M_B_CPU1_SB_DQ<22>")
	)
	(segment
		(start 89.287096 -226.33305)
		(end 89.272364 -226.341686)
		(width 0.088646)
		(layer "In2.Cu")
		(net "M_B_CPU1_SB_DQ<22>")
	)
	(segment
		(start 59.296808 -205.525624)
		(end 58.963814 -205.19263)
		(width 0.18288)
		(layer "In2.Cu")
		(net "M_B_CPU1_SB_DQ<22>")
	)
	(segment
		(start 68.976748 -205.9432)
		(end 68.783708 -206.13624)
		(width 0.18288)
		(layer "In2.Cu")
		(net "M_B_CPU1_SB_DQ<22>")
	)
	(segment
		(start 68.783708 -206.722726)
		(end 68.590668 -206.915766)
		(width 0.18288)
		(layer "In2.Cu")
		(net "M_B_CPU1_SB_DQ<22>")
	)
	(segment
		(start 88.897968 -224.7138)
		(end 88.889078 -224.70872)
		(width 0.088646)
		(layer "In2.Cu")
		(net "M_B_CPU1_SB_DQ<22>")
	)
	(segment
		(start 67.82054 -206.915766)
		(end 67.6275 -206.722726)
		(width 0.18288)
		(layer "In2.Cu")
		(net "M_B_CPU1_SB_DQ<22>")
	)
	(segment
		(start 59.954922 -205.525624)
		(end 59.296808 -205.525624)
		(width 0.18288)
		(layer "In2.Cu")
		(net "M_B_CPU1_SB_DQ<22>")
	)
	(segment
		(start 69.919596 -206.899764)
		(end 69.726556 -206.706724)
		(width 0.18288)
		(layer "In2.Cu")
		(net "M_B_CPU1_SB_DQ<22>")
	)
	(segment
		(start 54.12867 -206.409798)
		(end 52.65801 -206.409798)
		(width 0.18288)
		(layer "In2.Cu")
		(net "M_B_CPU1_SB_DQ<22>")
	)
	(segment
		(start 56.894222 -205.620112)
		(end 56.611774 -205.337664)
		(width 0.18288)
		(layer "In2.Cu")
		(net "M_B_CPU1_SB_DQ<22>")
	)
	(segment
		(start 69.726556 -206.13624)
		(end 69.533516 -205.9432)
		(width 0.18288)
		(layer "In2.Cu")
		(net "M_B_CPU1_SB_DQ<22>")
	)
	(segment
		(start 69.533516 -205.9432)
		(end 68.976748 -205.9432)
		(width 0.18288)
		(layer "In2.Cu")
		(net "M_B_CPU1_SB_DQ<22>")
	)
	(segment
		(start 85.518498 -221.099634)
		(end 85.37575 -220.956886)
		(width 0.18288)
		(layer "In2.Cu")
		(net "M_B_CPU1_SB_DQ<22>")
	)
	(segment
		(start 58.17743 -205.620112)
		(end 56.894222 -205.620112)
		(width 0.18288)
		(layer "In2.Cu")
		(net "M_B_CPU1_SB_DQ<22>")
	)
	(arc
		(start 88.710516 -224.389442)
		(mid 88.636525 -224.109876)
		(end 88.43391 -223.90354)
		(width 0.088646)
		(layer "In2.Cu")
		(net "M_B_CPU1_SB_DQ<22>")
	)
	(arc
		(start 88.4174 -223.893888)
		(mid 88.139222 -223.824165)
		(end 87.862664 -223.899984)
		(width 0.088646)
		(layer "In2.Cu")
		(net "M_B_CPU1_SB_DQ<22>")
	)
	(arc
		(start 89.180416 -225.193352)
		(mid 89.102305 -224.916403)
		(end 88.897968 -224.7138)
		(width 0.088646)
		(layer "In2.Cu")
		(net "M_B_CPU1_SB_DQ<22>")
	)
	(arc
		(start 89.837768 -226.341686)
		(mid 89.563569 -226.265851)
		(end 89.287096 -226.33305)
		(width 0.088646)
		(layer "In2.Cu")
		(net "M_B_CPU1_SB_DQ<22>")
	)
	(arc
		(start 87.862664 -223.899984)
		(mid 87.675466 -223.950127)
		(end 87.488268 -223.899984)
		(width 0.088646)
		(layer "In2.Cu")
		(net "M_B_CPU1_SB_DQ<22>")
	)
	(arc
		(start 88.889078 -226.336606)
		(mid 88.710481 -226.017328)
		(end 88.889078 -225.69805)
		(width 0.088646)
		(layer "In2.Cu")
		(net "M_B_CPU1_SB_DQ<22>")
	)
	(arc
		(start 86.830916 -222.75165)
		(mid 86.752805 -222.474701)
		(end 86.548468 -222.272098)
		(width 0.088646)
		(layer "In2.Cu")
		(net "M_B_CPU1_SB_DQ<22>")
	)
	(arc
		(start 87.009478 -223.080834)
		(mid 86.878564 -222.944474)
		(end 86.830916 -222.761556)
		(width 0.088646)
		(layer "In2.Cu")
		(net "M_B_CPU1_SB_DQ<22>")
	)
	(arc
		(start 88.897968 -225.69297)
		(mid 89.100254 -225.493989)
		(end 89.180416 -225.2218)
		(width 0.088646)
		(layer "In2.Cu")
		(net "M_B_CPU1_SB_DQ<22>")
	)
	(arc
		(start 87.479378 -223.894904)
		(mid 87.348464 -223.758544)
		(end 87.300816 -223.575626)
		(width 0.088646)
		(layer "In2.Cu")
		(net "M_B_CPU1_SB_DQ<22>")
	)
	(arc
		(start 88.889078 -224.70872)
		(mid 88.758164 -224.57236)
		(end 88.710516 -224.389442)
		(width 0.088646)
		(layer "In2.Cu")
		(net "M_B_CPU1_SB_DQ<22>")
	)
	(arc
		(start 89.272364 -226.341686)
		(mid 89.085166 -226.391829)
		(end 88.897968 -226.341686)
		(width 0.088646)
		(layer "In2.Cu")
		(net "M_B_CPU1_SB_DQ<22>")
	)
	(arc
		(start 87.300816 -223.557084)
		(mid 87.220654 -223.284895)
		(end 87.018368 -223.085914)
		(width 0.088646)
		(layer "In2.Cu")
		(net "M_B_CPU1_SB_DQ<22>")
	)
	(arc
		(start 90.475308 -226.831144)
		(mid 90.172557 -226.565549)
		(end 89.837768 -226.341686)
		(width 0.088646)
		(layer "In2.Cu")
		(net "M_B_CPU1_SB_DQ<22>")
	)
	(arc
		(start 86.548468 -222.272098)
		(mid 86.507659 -222.244926)
		(end 86.470744 -222.212662)
		(width 0.088646)
		(layer "In2.Cu")
		(net "M_B_CPU1_SB_DQ<22>")
	)
	(segment
		(start 44.22013 -205.816708)
		(end 43.795188 -205.391766)
		(width 0.20066)
		(layer "F.Cu")
		(net "M_B_CPU1_SB_DQ<21>")
	)
	(segment
		(start 39.861236 -206.028036)
		(end 39.649908 -205.816708)
		(width 0.20066)
		(layer "F.Cu")
		(net "M_B_CPU1_SB_DQ<21>")
	)
	(segment
		(start 43.616626 -205.391766)
		(end 43.285918 -205.391766)
		(width 0.101854)
		(layer "F.Cu")
		(net "M_B_CPU1_SB_DQ<21>")
	)
	(segment
		(start 89.085166 -226.553014)
		(end 89.085166 -226.017328)
		(width 0.20066)
		(layer "F.Cu")
		(net "M_B_CPU1_SB_DQ<21>")
	)
	(segment
		(start 40.520112 -205.873604)
		(end 40.36568 -206.028036)
		(width 0.20066)
		(layer "F.Cu")
		(net "M_B_CPU1_SB_DQ<21>")
	)
	(segment
		(start 43.285918 -205.391766)
		(end 41.3004 -205.391766)
		(width 0.1016)
		(layer "F.Cu")
		(net "M_B_CPU1_SB_DQ<21>")
	)
	(segment
		(start 41.29151 -205.382876)
		(end 40.682672 -205.382876)
		(width 0.20066)
		(layer "F.Cu")
		(net "M_B_CPU1_SB_DQ<21>")
	)
	(segment
		(start 40.520112 -205.545436)
		(end 40.520112 -205.873604)
		(width 0.20066)
		(layer "F.Cu")
		(net "M_B_CPU1_SB_DQ<21>")
	)
	(segment
		(start 40.682672 -205.382876)
		(end 40.520112 -205.545436)
		(width 0.20066)
		(layer "F.Cu")
		(net "M_B_CPU1_SB_DQ<21>")
	)
	(segment
		(start 45.859446 -205.816708)
		(end 44.22013 -205.816708)
		(width 0.20066)
		(layer "F.Cu")
		(net "M_B_CPU1_SB_DQ<21>")
	)
	(segment
		(start 40.36568 -206.028036)
		(end 39.861236 -206.028036)
		(width 0.20066)
		(layer "F.Cu")
		(net "M_B_CPU1_SB_DQ<21>")
	)
	(segment
		(start 41.3004 -205.391766)
		(end 41.29151 -205.382876)
		(width 0.1016)
		(layer "F.Cu")
		(net "M_B_CPU1_SB_DQ<21>")
	)
	(segment
		(start 89.084912 -226.553268)
		(end 89.085166 -226.553014)
		(width 0.20066)
		(layer "F.Cu")
		(net "M_B_CPU1_SB_DQ<21>")
	)
	(segment
		(start 39.649908 -205.816708)
		(end 38.315646 -205.816708)
		(width 0.20066)
		(layer "F.Cu")
		(net "M_B_CPU1_SB_DQ<21>")
	)
	(segment
		(start 46.964346 -205.816708)
		(end 45.859446 -205.816708)
		(width 0.20066)
		(layer "F.Cu")
		(net "M_B_CPU1_SB_DQ<21>")
	)
	(segment
		(start 43.795188 -205.391766)
		(end 43.616626 -205.391766)
		(width 0.20066)
		(layer "F.Cu")
		(net "M_B_CPU1_SB_DQ<21>")
	)
	(segment
		(start 64.052704 -204.67701)
		(end 62.513718 -204.67701)
		(width 0.18288)
		(layer "In2.Cu")
		(net "M_B_CPU1_SB_DQ<21>")
	)
	(segment
		(start 89.085166 -226.017328)
		(end 89.39784 -226.017328)
		(width 0.088646)
		(layer "In2.Cu")
		(net "M_B_CPU1_SB_DQ<21>")
	)
	(segment
		(start 62.513718 -204.67701)
		(end 62.255146 -204.418438)
		(width 0.18288)
		(layer "In2.Cu")
		(net "M_B_CPU1_SB_DQ<21>")
	)
	(segment
		(start 58.850276 -204.674216)
		(end 58.487818 -204.674216)
		(width 0.18288)
		(layer "In2.Cu")
		(net "M_B_CPU1_SB_DQ<21>")
	)
	(segment
		(start 86.5759 -221.29496)
		(end 86.43366 -221.29496)
		(width 0.088646)
		(layer "In2.Cu")
		(net "M_B_CPU1_SB_DQ<21>")
	)
	(segment
		(start 55.710582 -204.588872)
		(end 54.824884 -205.47457)
		(width 0.18288)
		(layer "In2.Cu")
		(net "M_B_CPU1_SB_DQ<21>")
	)
	(segment
		(start 54.824884 -205.47457)
		(end 54.297326 -205.47457)
		(width 0.18288)
		(layer "In2.Cu")
		(net "M_B_CPU1_SB_DQ<21>")
	)
	(segment
		(start 53.97627 -205.153514)
		(end 52.787804 -205.153514)
		(width 0.18288)
		(layer "In2.Cu")
		(net "M_B_CPU1_SB_DQ<21>")
	)
	(segment
		(start 69.80555 -205.422246)
		(end 67.346322 -205.422246)
		(width 0.18288)
		(layer "In2.Cu")
		(net "M_B_CPU1_SB_DQ<21>")
	)
	(segment
		(start 67.346322 -205.422246)
		(end 66.467482 -204.543406)
		(width 0.18288)
		(layer "In2.Cu")
		(net "M_B_CPU1_SB_DQ<21>")
	)
	(segment
		(start 47.578518 -205.202536)
		(end 46.964346 -205.816708)
		(width 0.18288)
		(layer "In2.Cu")
		(net "M_B_CPU1_SB_DQ<21>")
	)
	(segment
		(start 66.467482 -204.543406)
		(end 65.97523 -204.543406)
		(width 0.18288)
		(layer "In2.Cu")
		(net "M_B_CPU1_SB_DQ<21>")
	)
	(segment
		(start 54.297326 -205.47457)
		(end 53.97627 -205.153514)
		(width 0.18288)
		(layer "In2.Cu")
		(net "M_B_CPU1_SB_DQ<21>")
	)
	(segment
		(start 59.005978 -204.518514)
		(end 58.850276 -204.674216)
		(width 0.18288)
		(layer "In2.Cu")
		(net "M_B_CPU1_SB_DQ<21>")
	)
	(segment
		(start 48.971454 -205.202536)
		(end 47.578518 -205.202536)
		(width 0.18288)
		(layer "In2.Cu")
		(net "M_B_CPU1_SB_DQ<21>")
	)
	(segment
		(start 86.827868 -221.546928)
		(end 86.5759 -221.29496)
		(width 0.088646)
		(layer "In2.Cu")
		(net "M_B_CPU1_SB_DQ<21>")
	)
	(segment
		(start 84.812378 -220.429074)
		(end 69.80555 -205.422246)
		(width 0.18288)
		(layer "In2.Cu")
		(net "M_B_CPU1_SB_DQ<21>")
	)
	(segment
		(start 61.830204 -204.518514)
		(end 59.005978 -204.518514)
		(width 0.18288)
		(layer "In2.Cu")
		(net "M_B_CPU1_SB_DQ<21>")
	)
	(segment
		(start 61.93028 -204.418438)
		(end 61.830204 -204.518514)
		(width 0.18288)
		(layer "In2.Cu")
		(net "M_B_CPU1_SB_DQ<21>")
	)
	(segment
		(start 51.567588 -205.64348)
		(end 51.315874 -205.391766)
		(width 0.18288)
		(layer "In2.Cu")
		(net "M_B_CPU1_SB_DQ<21>")
	)
	(segment
		(start 51.315874 -205.391766)
		(end 49.160684 -205.391766)
		(width 0.18288)
		(layer "In2.Cu")
		(net "M_B_CPU1_SB_DQ<21>")
	)
	(segment
		(start 62.255146 -204.418438)
		(end 61.93028 -204.418438)
		(width 0.18288)
		(layer "In2.Cu")
		(net "M_B_CPU1_SB_DQ<21>")
	)
	(segment
		(start 89.281254 -224.070164)
		(end 89.272364 -224.065084)
		(width 0.088646)
		(layer "In2.Cu")
		(net "M_B_CPU1_SB_DQ<21>")
	)
	(segment
		(start 64.288162 -204.441552)
		(end 64.052704 -204.67701)
		(width 0.18288)
		(layer "In2.Cu")
		(net "M_B_CPU1_SB_DQ<21>")
	)
	(segment
		(start 52.297838 -205.64348)
		(end 51.567588 -205.64348)
		(width 0.18288)
		(layer "In2.Cu")
		(net "M_B_CPU1_SB_DQ<21>")
	)
	(segment
		(start 56.83885 -204.367384)
		(end 56.617362 -204.588872)
		(width 0.18288)
		(layer "In2.Cu")
		(net "M_B_CPU1_SB_DQ<21>")
	)
	(segment
		(start 65.97523 -204.543406)
		(end 65.873376 -204.441552)
		(width 0.18288)
		(layer "In2.Cu")
		(net "M_B_CPU1_SB_DQ<21>")
	)
	(segment
		(start 88.8111 -223.256348)
		(end 88.80221 -223.251268)
		(width 0.088646)
		(layer "In2.Cu")
		(net "M_B_CPU1_SB_DQ<21>")
	)
	(segment
		(start 87.110316 -221.957646)
		(end 87.110316 -221.94774)
		(width 0.088646)
		(layer "In2.Cu")
		(net "M_B_CPU1_SB_DQ<21>")
	)
	(segment
		(start 52.787804 -205.153514)
		(end 52.297838 -205.64348)
		(width 0.18288)
		(layer "In2.Cu")
		(net "M_B_CPU1_SB_DQ<21>")
	)
	(segment
		(start 89.39784 -226.017328)
		(end 89.463118 -225.95205)
		(width 0.088646)
		(layer "In2.Cu")
		(net "M_B_CPU1_SB_DQ<21>")
	)
	(segment
		(start 88.43645 -223.246442)
		(end 88.428068 -223.251268)
		(width 0.088646)
		(layer "In2.Cu")
		(net "M_B_CPU1_SB_DQ<21>")
	)
	(segment
		(start 89.7509 -224.88398)
		(end 89.74201 -224.8789)
		(width 0.088646)
		(layer "In2.Cu")
		(net "M_B_CPU1_SB_DQ<21>")
	)
	(segment
		(start 56.617362 -204.588872)
		(end 55.710582 -204.588872)
		(width 0.18288)
		(layer "In2.Cu")
		(net "M_B_CPU1_SB_DQ<21>")
	)
	(segment
		(start 58.180986 -204.367384)
		(end 56.83885 -204.367384)
		(width 0.18288)
		(layer "In2.Cu")
		(net "M_B_CPU1_SB_DQ<21>")
	)
	(segment
		(start 85.878416 -220.739716)
		(end 85.567774 -220.429074)
		(width 0.18288)
		(layer "In2.Cu")
		(net "M_B_CPU1_SB_DQ<21>")
	)
	(segment
		(start 89.272364 -224.065084)
		(end 89.260172 -224.057972)
		(width 0.088646)
		(layer "In2.Cu")
		(net "M_B_CPU1_SB_DQ<21>")
	)
	(segment
		(start 87.401654 -222.442278)
		(end 87.392764 -222.437198)
		(width 0.088646)
		(layer "In2.Cu")
		(net "M_B_CPU1_SB_DQ<21>")
	)
	(segment
		(start 89.459816 -224.404936)
		(end 89.459816 -224.389442)
		(width 0.088646)
		(layer "In2.Cu")
		(net "M_B_CPU1_SB_DQ<21>")
	)
	(segment
		(start 58.487818 -204.674216)
		(end 58.180986 -204.367384)
		(width 0.18288)
		(layer "In2.Cu")
		(net "M_B_CPU1_SB_DQ<21>")
	)
	(segment
		(start 86.43366 -221.29496)
		(end 85.878416 -220.739716)
		(width 0.088646)
		(layer "In2.Cu")
		(net "M_B_CPU1_SB_DQ<21>")
	)
	(segment
		(start 89.74201 -225.527616)
		(end 89.7509 -225.522536)
		(width 0.088646)
		(layer "In2.Cu")
		(net "M_B_CPU1_SB_DQ<21>")
	)
	(segment
		(start 85.567774 -220.429074)
		(end 84.812378 -220.429074)
		(width 0.18288)
		(layer "In2.Cu")
		(net "M_B_CPU1_SB_DQ<21>")
	)
	(segment
		(start 87.580216 -222.77578)
		(end 87.580216 -222.761556)
		(width 0.088646)
		(layer "In2.Cu")
		(net "M_B_CPU1_SB_DQ<21>")
	)
	(segment
		(start 49.160684 -205.391766)
		(end 48.971454 -205.202536)
		(width 0.18288)
		(layer "In2.Cu")
		(net "M_B_CPU1_SB_DQ<21>")
	)
	(segment
		(start 88.428068 -223.251268)
		(end 88.413336 -223.259904)
		(width 0.088646)
		(layer "In2.Cu")
		(net "M_B_CPU1_SB_DQ<21>")
	)
	(segment
		(start 65.873376 -204.441552)
		(end 64.288162 -204.441552)
		(width 0.18288)
		(layer "In2.Cu")
		(net "M_B_CPU1_SB_DQ<21>")
	)
	(arc
		(start 89.74201 -224.8789)
		(mid 89.539187 -224.678669)
		(end 89.459816 -224.404936)
		(width 0.088646)
		(layer "In2.Cu")
		(net "M_B_CPU1_SB_DQ<21>")
	)
	(arc
		(start 87.862664 -223.251268)
		(mid 87.659359 -223.050402)
		(end 87.580216 -222.77578)
		(width 0.088646)
		(layer "In2.Cu")
		(net "M_B_CPU1_SB_DQ<21>")
	)
	(arc
		(start 87.392764 -222.437198)
		(mid 87.188429 -222.234593)
		(end 87.110316 -221.957646)
		(width 0.088646)
		(layer "In2.Cu")
		(net "M_B_CPU1_SB_DQ<21>")
	)
	(arc
		(start 89.459816 -224.389442)
		(mid 89.412137 -224.206542)
		(end 89.281254 -224.070164)
		(width 0.088646)
		(layer "In2.Cu")
		(net "M_B_CPU1_SB_DQ<21>")
	)
	(arc
		(start 86.931754 -221.628462)
		(mid 86.927424 -221.625815)
		(end 86.923118 -221.623128)
		(width 0.088646)
		(layer "In2.Cu")
		(net "M_B_CPU1_SB_DQ<21>")
	)
	(arc
		(start 87.580216 -222.761556)
		(mid 87.532537 -222.578656)
		(end 87.401654 -222.442278)
		(width 0.088646)
		(layer "In2.Cu")
		(net "M_B_CPU1_SB_DQ<21>")
	)
	(arc
		(start 88.989662 -223.575626)
		(mid 88.941983 -223.392726)
		(end 88.8111 -223.256348)
		(width 0.088646)
		(layer "In2.Cu")
		(net "M_B_CPU1_SB_DQ<21>")
	)
	(arc
		(start 88.80221 -223.251268)
		(mid 88.619959 -223.201157)
		(end 88.43645 -223.246442)
		(width 0.088646)
		(layer "In2.Cu")
		(net "M_B_CPU1_SB_DQ<21>")
	)
	(arc
		(start 89.7509 -225.522536)
		(mid 89.929497 -225.203258)
		(end 89.7509 -224.88398)
		(width 0.088646)
		(layer "In2.Cu")
		(net "M_B_CPU1_SB_DQ<21>")
	)
	(arc
		(start 89.260172 -224.057972)
		(mid 89.061944 -223.852124)
		(end 88.989662 -223.575626)
		(width 0.088646)
		(layer "In2.Cu")
		(net "M_B_CPU1_SB_DQ<21>")
	)
	(arc
		(start 89.463118 -225.95205)
		(mid 89.552232 -225.706753)
		(end 89.74201 -225.527616)
		(width 0.088646)
		(layer "In2.Cu")
		(net "M_B_CPU1_SB_DQ<21>")
	)
	(arc
		(start 86.923118 -221.623128)
		(mid 86.920963 -221.621851)
		(end 86.9188 -221.620588)
		(width 0.088646)
		(layer "In2.Cu")
		(net "M_B_CPU1_SB_DQ<21>")
	)
	(arc
		(start 87.110316 -221.94774)
		(mid 87.062637 -221.76484)
		(end 86.931754 -221.628462)
		(width 0.088646)
		(layer "In2.Cu")
		(net "M_B_CPU1_SB_DQ<21>")
	)
	(arc
		(start 88.413336 -223.259904)
		(mid 88.136895 -223.32707)
		(end 87.862664 -223.251268)
		(width 0.088646)
		(layer "In2.Cu")
		(net "M_B_CPU1_SB_DQ<21>")
	)
	(arc
		(start 86.9188 -221.620588)
		(mid 86.871426 -221.586113)
		(end 86.827868 -221.546928)
		(width 0.088646)
		(layer "In2.Cu")
		(net "M_B_CPU1_SB_DQ<21>")
	)
	(segment
		(start 40.520112 -207.29321)
		(end 40.520112 -207.58277)
		(width 0.20066)
		(layer "F.Cu")
		(net "M_B_CPU1_SB_DQ<20>")
	)
	(segment
		(start 88.615266 -227.367084)
		(end 88.615266 -226.831398)
		(width 0.20066)
		(layer "F.Cu")
		(net "M_B_CPU1_SB_DQ<20>")
	)
	(segment
		(start 39.649908 -207.51673)
		(end 38.315646 -207.51673)
		(width 0.20066)
		(layer "F.Cu")
		(net "M_B_CPU1_SB_DQ<20>")
	)
	(segment
		(start 44.065444 -207.091788)
		(end 43.616626 -207.091788)
		(width 0.20066)
		(layer "F.Cu")
		(net "M_B_CPU1_SB_DQ<20>")
	)
	(segment
		(start 40.520112 -207.58277)
		(end 40.347392 -207.75549)
		(width 0.20066)
		(layer "F.Cu")
		(net "M_B_CPU1_SB_DQ<20>")
	)
	(segment
		(start 43.616626 -207.091788)
		(end 41.547542 -207.091788)
		(width 0.1016)
		(layer "F.Cu")
		(net "M_B_CPU1_SB_DQ<20>")
	)
	(segment
		(start 41.299638 -207.091788)
		(end 41.29151 -207.08366)
		(width 0.101854)
		(layer "F.Cu")
		(net "M_B_CPU1_SB_DQ<20>")
	)
	(segment
		(start 40.347392 -207.75549)
		(end 39.888668 -207.75549)
		(width 0.20066)
		(layer "F.Cu")
		(net "M_B_CPU1_SB_DQ<20>")
	)
	(segment
		(start 41.29151 -207.08366)
		(end 40.729662 -207.08366)
		(width 0.20066)
		(layer "F.Cu")
		(net "M_B_CPU1_SB_DQ<20>")
	)
	(segment
		(start 40.729662 -207.08366)
		(end 40.520112 -207.29321)
		(width 0.20066)
		(layer "F.Cu")
		(net "M_B_CPU1_SB_DQ<20>")
	)
	(segment
		(start 39.888668 -207.75549)
		(end 39.649908 -207.51673)
		(width 0.20066)
		(layer "F.Cu")
		(net "M_B_CPU1_SB_DQ<20>")
	)
	(segment
		(start 46.964346 -207.51673)
		(end 45.859446 -207.51673)
		(width 0.20066)
		(layer "F.Cu")
		(net "M_B_CPU1_SB_DQ<20>")
	)
	(segment
		(start 88.615266 -226.831398)
		(end 88.615012 -226.831144)
		(width 0.20066)
		(layer "F.Cu")
		(net "M_B_CPU1_SB_DQ<20>")
	)
	(segment
		(start 45.859446 -207.51673)
		(end 44.490386 -207.51673)
		(width 0.20066)
		(layer "F.Cu")
		(net "M_B_CPU1_SB_DQ<20>")
	)
	(segment
		(start 41.547542 -207.091788)
		(end 41.299638 -207.091788)
		(width 0.101854)
		(layer "F.Cu")
		(net "M_B_CPU1_SB_DQ<20>")
	)
	(segment
		(start 44.490386 -207.51673)
		(end 44.065444 -207.091788)
		(width 0.20066)
		(layer "F.Cu")
		(net "M_B_CPU1_SB_DQ<20>")
	)
	(segment
		(start 52.311046 -207.307434)
		(end 51.67884 -207.307434)
		(width 0.18288)
		(layer "In2.Cu")
		(net "M_B_CPU1_SB_DQ<20>")
	)
	(segment
		(start 63.118238 -207.07985)
		(end 62.925198 -206.88681)
		(width 0.18288)
		(layer "In2.Cu")
		(net "M_B_CPU1_SB_DQ<20>")
	)
	(segment
		(start 59.228228 -206.050134)
		(end 58.96356 -206.314802)
		(width 0.18288)
		(layer "In2.Cu")
		(net "M_B_CPU1_SB_DQ<20>")
	)
	(segment
		(start 63.710058 -206.661004)
		(end 63.710058 -206.91475)
		(width 0.18288)
		(layer "In2.Cu")
		(net "M_B_CPU1_SB_DQ<20>")
	)
	(segment
		(start 62.925198 -206.145384)
		(end 62.731904 -205.95209)
		(width 0.18288)
		(layer "In2.Cu")
		(net "M_B_CPU1_SB_DQ<20>")
	)
	(segment
		(start 85.213952 -221.506796)
		(end 84.356956 -221.506796)
		(width 0.18288)
		(layer "In2.Cu")
		(net "M_B_CPU1_SB_DQ<20>")
	)
	(segment
		(start 54.128416 -206.940404)
		(end 52.678076 -206.940404)
		(width 0.18288)
		(layer "In2.Cu")
		(net "M_B_CPU1_SB_DQ<20>")
	)
	(segment
		(start 58.96356 -206.314802)
		(end 58.347102 -206.314802)
		(width 0.18288)
		(layer "In2.Cu")
		(net "M_B_CPU1_SB_DQ<20>")
	)
	(segment
		(start 64.15151 -206.219552)
		(end 63.710058 -206.661004)
		(width 0.18288)
		(layer "In2.Cu")
		(net "M_B_CPU1_SB_DQ<20>")
	)
	(segment
		(start 86.640416 -222.780098)
		(end 86.640416 -222.761556)
		(width 0.088646)
		(layer "In2.Cu")
		(net "M_B_CPU1_SB_DQ<20>")
	)
	(segment
		(start 65.90284 -206.219552)
		(end 64.15151 -206.219552)
		(width 0.18288)
		(layer "In2.Cu")
		(net "M_B_CPU1_SB_DQ<20>")
	)
	(segment
		(start 62.731904 -205.95209)
		(end 62.028324 -205.95209)
		(width 0.18288)
		(layer "In2.Cu")
		(net "M_B_CPU1_SB_DQ<20>")
	)
	(segment
		(start 87.110316 -223.585532)
		(end 87.110316 -223.575626)
		(width 0.088646)
		(layer "In2.Cu")
		(net "M_B_CPU1_SB_DQ<20>")
	)
	(segment
		(start 88.989662 -225.211894)
		(end 88.989662 -225.194622)
		(width 0.088646)
		(layer "In2.Cu")
		(net "M_B_CPU1_SB_DQ<20>")
	)
	(segment
		(start 86.33587 -222.347536)
		(end 85.49513 -221.506796)
		(width 0.088646)
		(layer "In2.Cu")
		(net "M_B_CPU1_SB_DQ<20>")
	)
	(segment
		(start 62.028324 -205.95209)
		(end 61.781944 -206.19847)
		(width 0.18288)
		(layer "In2.Cu")
		(net "M_B_CPU1_SB_DQ<20>")
	)
	(segment
		(start 63.544958 -207.07985)
		(end 63.118238 -207.07985)
		(width 0.18288)
		(layer "In2.Cu")
		(net "M_B_CPU1_SB_DQ<20>")
	)
	(segment
		(start 51.67884 -207.307434)
		(end 51.46294 -207.091534)
		(width 0.18288)
		(layer "In2.Cu")
		(net "M_B_CPU1_SB_DQ<20>")
	)
	(segment
		(start 86.931754 -223.256348)
		(end 86.922864 -223.251268)
		(width 0.088646)
		(layer "In2.Cu")
		(net "M_B_CPU1_SB_DQ<20>")
	)
	(segment
		(start 67.107054 -207.423766)
		(end 65.90284 -206.219552)
		(width 0.18288)
		(layer "In2.Cu")
		(net "M_B_CPU1_SB_DQ<20>")
	)
	(segment
		(start 85.49513 -221.506796)
		(end 85.213952 -221.506796)
		(width 0.088646)
		(layer "In2.Cu")
		(net "M_B_CPU1_SB_DQ<20>")
	)
	(segment
		(start 63.710058 -206.91475)
		(end 63.544958 -207.07985)
		(width 0.18288)
		(layer "In2.Cu")
		(net "M_B_CPU1_SB_DQ<20>")
	)
	(segment
		(start 49.098708 -207.091534)
		(end 48.903382 -206.896208)
		(width 0.18288)
		(layer "In2.Cu")
		(net "M_B_CPU1_SB_DQ<20>")
	)
	(segment
		(start 70.273926 -207.423766)
		(end 67.107054 -207.423766)
		(width 0.18288)
		(layer "In2.Cu")
		(net "M_B_CPU1_SB_DQ<20>")
	)
	(segment
		(start 58.347102 -206.314802)
		(end 58.274712 -206.242412)
		(width 0.18288)
		(layer "In2.Cu")
		(net "M_B_CPU1_SB_DQ<20>")
	)
	(segment
		(start 54.297326 -207.109314)
		(end 54.128416 -206.940404)
		(width 0.18288)
		(layer "In2.Cu")
		(net "M_B_CPU1_SB_DQ<20>")
	)
	(segment
		(start 62.925198 -206.88681)
		(end 62.925198 -206.145384)
		(width 0.18288)
		(layer "In2.Cu")
		(net "M_B_CPU1_SB_DQ<20>")
	)
	(segment
		(start 60.065666 -206.19847)
		(end 59.91733 -206.050134)
		(width 0.18288)
		(layer "In2.Cu")
		(net "M_B_CPU1_SB_DQ<20>")
	)
	(segment
		(start 84.356956 -221.506796)
		(end 70.273926 -207.423766)
		(width 0.18288)
		(layer "In2.Cu")
		(net "M_B_CPU1_SB_DQ<20>")
	)
	(segment
		(start 88.341454 -224.070164)
		(end 88.332564 -224.065084)
		(width 0.088646)
		(layer "In2.Cu")
		(net "M_B_CPU1_SB_DQ<20>")
	)
	(segment
		(start 51.46294 -207.091534)
		(end 49.098708 -207.091534)
		(width 0.18288)
		(layer "In2.Cu")
		(net "M_B_CPU1_SB_DQ<20>")
	)
	(segment
		(start 59.91733 -206.050134)
		(end 59.228228 -206.050134)
		(width 0.18288)
		(layer "In2.Cu")
		(net "M_B_CPU1_SB_DQ<20>")
	)
	(segment
		(start 47.584868 -206.896208)
		(end 46.964346 -207.51673)
		(width 0.18288)
		(layer "In2.Cu")
		(net "M_B_CPU1_SB_DQ<20>")
	)
	(segment
		(start 88.615012 -226.831144)
		(end 88.577674 -226.266502)
		(width 0.088646)
		(layer "In2.Cu")
		(net "M_B_CPU1_SB_DQ<20>")
	)
	(segment
		(start 48.903382 -206.896208)
		(end 47.584868 -206.896208)
		(width 0.18288)
		(layer "In2.Cu")
		(net "M_B_CPU1_SB_DQ<20>")
	)
	(segment
		(start 56.68645 -206.242412)
		(end 55.819548 -207.109314)
		(width 0.18288)
		(layer "In2.Cu")
		(net "M_B_CPU1_SB_DQ<20>")
	)
	(segment
		(start 55.819548 -207.109314)
		(end 54.297326 -207.109314)
		(width 0.18288)
		(layer "In2.Cu")
		(net "M_B_CPU1_SB_DQ<20>")
	)
	(segment
		(start 52.678076 -206.940404)
		(end 52.311046 -207.307434)
		(width 0.18288)
		(layer "In2.Cu")
		(net "M_B_CPU1_SB_DQ<20>")
	)
	(segment
		(start 58.274712 -206.242412)
		(end 56.68645 -206.242412)
		(width 0.18288)
		(layer "In2.Cu")
		(net "M_B_CPU1_SB_DQ<20>")
	)
	(segment
		(start 88.520016 -226.032822)
		(end 88.520016 -225.998786)
		(width 0.088646)
		(layer "In2.Cu")
		(net "M_B_CPU1_SB_DQ<20>")
	)
	(segment
		(start 88.520016 -224.399348)
		(end 88.520016 -224.389442)
		(width 0.088646)
		(layer "In2.Cu")
		(net "M_B_CPU1_SB_DQ<20>")
	)
	(segment
		(start 61.781944 -206.19847)
		(end 60.065666 -206.19847)
		(width 0.18288)
		(layer "In2.Cu")
		(net "M_B_CPU1_SB_DQ<20>")
	)
	(arc
		(start 88.520016 -224.389442)
		(mid 88.472337 -224.206542)
		(end 88.341454 -224.070164)
		(width 0.088646)
		(layer "In2.Cu")
		(net "M_B_CPU1_SB_DQ<20>")
	)
	(arc
		(start 87.110316 -223.575626)
		(mid 87.062637 -223.392726)
		(end 86.931754 -223.256348)
		(width 0.088646)
		(layer "In2.Cu")
		(net "M_B_CPU1_SB_DQ<20>")
	)
	(arc
		(start 87.392764 -224.065084)
		(mid 87.188429 -223.862479)
		(end 87.110316 -223.585532)
		(width 0.088646)
		(layer "In2.Cu")
		(net "M_B_CPU1_SB_DQ<20>")
	)
	(arc
		(start 88.802464 -224.8789)
		(mid 88.598129 -224.676295)
		(end 88.520016 -224.399348)
		(width 0.088646)
		(layer "In2.Cu")
		(net "M_B_CPU1_SB_DQ<20>")
	)
	(arc
		(start 86.461854 -222.442278)
		(mid 86.39555 -222.399312)
		(end 86.33587 -222.347536)
		(width 0.088646)
		(layer "In2.Cu")
		(net "M_B_CPU1_SB_DQ<20>")
	)
	(arc
		(start 88.520016 -225.998786)
		(mid 88.600178 -225.726597)
		(end 88.802464 -225.527616)
		(width 0.088646)
		(layer "In2.Cu")
		(net "M_B_CPU1_SB_DQ<20>")
	)
	(arc
		(start 86.922864 -223.251268)
		(mid 86.720578 -223.052287)
		(end 86.640416 -222.780098)
		(width 0.088646)
		(layer "In2.Cu")
		(net "M_B_CPU1_SB_DQ<20>")
	)
	(arc
		(start 88.577674 -226.266502)
		(mid 88.536265 -226.152766)
		(end 88.520016 -226.032822)
		(width 0.088646)
		(layer "In2.Cu")
		(net "M_B_CPU1_SB_DQ<20>")
	)
	(arc
		(start 88.989662 -225.194622)
		(mid 88.937392 -225.012257)
		(end 88.802464 -224.8789)
		(width 0.088646)
		(layer "In2.Cu")
		(net "M_B_CPU1_SB_DQ<20>")
	)
	(arc
		(start 88.332564 -224.065084)
		(mid 88.145366 -224.014941)
		(end 87.958168 -224.065084)
		(width 0.088646)
		(layer "In2.Cu")
		(net "M_B_CPU1_SB_DQ<20>")
	)
	(arc
		(start 88.802464 -225.527616)
		(mid 88.937397 -225.394262)
		(end 88.989662 -225.211894)
		(width 0.088646)
		(layer "In2.Cu")
		(net "M_B_CPU1_SB_DQ<20>")
	)
	(arc
		(start 86.640416 -222.761556)
		(mid 86.592737 -222.578656)
		(end 86.461854 -222.442278)
		(width 0.088646)
		(layer "In2.Cu")
		(net "M_B_CPU1_SB_DQ<20>")
	)
	(arc
		(start 87.958168 -224.065084)
		(mid 87.675466 -224.14086)
		(end 87.392764 -224.065084)
		(width 0.088646)
		(layer "In2.Cu")
		(net "M_B_CPU1_SB_DQ<20>")
	)
	(segment
		(start 46.964346 -230.466646)
		(end 45.859446 -230.466646)
		(width 0.20066)
		(layer "F.Cu")
		(net "M_B_CPU1_SB_DQ<1>")
	)
	(segment
		(start 39.861236 -230.677974)
		(end 39.649908 -230.466646)
		(width 0.20066)
		(layer "F.Cu")
		(net "M_B_CPU1_SB_DQ<1>")
	)
	(segment
		(start 45.859446 -230.466646)
		(end 44.22013 -230.466646)
		(width 0.20066)
		(layer "F.Cu")
		(net "M_B_CPU1_SB_DQ<1>")
	)
	(segment
		(start 43.795188 -230.041704)
		(end 43.616626 -230.041704)
		(width 0.20066)
		(layer "F.Cu")
		(net "M_B_CPU1_SB_DQ<1>")
	)
	(segment
		(start 39.649908 -230.466646)
		(end 38.315646 -230.466646)
		(width 0.20066)
		(layer "F.Cu")
		(net "M_B_CPU1_SB_DQ<1>")
	)
	(segment
		(start 91.904312 -236.319822)
		(end 91.904566 -236.319568)
		(width 0.20066)
		(layer "F.Cu")
		(net "M_B_CPU1_SB_DQ<1>")
	)
	(segment
		(start 40.682672 -230.032814)
		(end 40.520112 -230.195374)
		(width 0.20066)
		(layer "F.Cu")
		(net "M_B_CPU1_SB_DQ<1>")
	)
	(segment
		(start 44.22013 -230.466646)
		(end 43.795188 -230.041704)
		(width 0.20066)
		(layer "F.Cu")
		(net "M_B_CPU1_SB_DQ<1>")
	)
	(segment
		(start 40.36568 -230.677974)
		(end 39.861236 -230.677974)
		(width 0.20066)
		(layer "F.Cu")
		(net "M_B_CPU1_SB_DQ<1>")
	)
	(segment
		(start 91.904566 -236.319568)
		(end 91.904566 -235.783882)
		(width 0.20066)
		(layer "F.Cu")
		(net "M_B_CPU1_SB_DQ<1>")
	)
	(segment
		(start 40.520112 -230.195374)
		(end 40.520112 -230.523542)
		(width 0.20066)
		(layer "F.Cu")
		(net "M_B_CPU1_SB_DQ<1>")
	)
	(segment
		(start 43.616626 -230.041704)
		(end 43.285918 -230.041704)
		(width 0.101854)
		(layer "F.Cu")
		(net "M_B_CPU1_SB_DQ<1>")
	)
	(segment
		(start 40.520112 -230.523542)
		(end 40.36568 -230.677974)
		(width 0.20066)
		(layer "F.Cu")
		(net "M_B_CPU1_SB_DQ<1>")
	)
	(segment
		(start 41.29151 -230.032814)
		(end 40.682672 -230.032814)
		(width 0.20066)
		(layer "F.Cu")
		(net "M_B_CPU1_SB_DQ<1>")
	)
	(segment
		(start 43.285918 -230.041704)
		(end 41.3004 -230.041704)
		(width 0.1016)
		(layer "F.Cu")
		(net "M_B_CPU1_SB_DQ<1>")
	)
	(segment
		(start 41.3004 -230.041704)
		(end 41.29151 -230.032814)
		(width 0.1016)
		(layer "F.Cu")
		(net "M_B_CPU1_SB_DQ<1>")
	)
	(segment
		(start 90.682064 -236.27334)
		(end 90.677492 -236.2708)
		(width 0.088646)
		(layer "In4.Cu")
		(net "M_B_CPU1_SB_DQ<1>")
	)
	(segment
		(start 50.105818 -230.041704)
		(end 49.922938 -229.858824)
		(width 0.18288)
		(layer "In4.Cu")
		(net "M_B_CPU1_SB_DQ<1>")
	)
	(segment
		(start 47.389288 -230.041704)
		(end 46.964346 -230.466646)
		(width 0.18288)
		(layer "In4.Cu")
		(net "M_B_CPU1_SB_DQ<1>")
	)
	(segment
		(start 91.32062 -236.231176)
		(end 91.247214 -236.27334)
		(width 0.088646)
		(layer "In4.Cu")
		(net "M_B_CPU1_SB_DQ<1>")
	)
	(segment
		(start 88.80983 -236.277658)
		(end 88.802464 -236.27334)
		(width 0.088646)
		(layer "In4.Cu")
		(net "M_B_CPU1_SB_DQ<1>")
	)
	(segment
		(start 56.916828 -229.91318)
		(end 55.678324 -229.91318)
		(width 0.18288)
		(layer "In4.Cu")
		(net "M_B_CPU1_SB_DQ<1>")
	)
	(segment
		(start 47.850298 -229.242366)
		(end 47.850298 -229.858824)
		(width 0.18288)
		(layer "In4.Cu")
		(net "M_B_CPU1_SB_DQ<1>")
	)
	(segment
		(start 49.740058 -229.285292)
		(end 49.414938 -229.285292)
		(width 0.18288)
		(layer "In4.Cu")
		(net "M_B_CPU1_SB_DQ<1>")
	)
	(segment
		(start 89.74963 -236.277658)
		(end 89.737692 -236.2708)
		(width 0.088646)
		(layer "In4.Cu")
		(net "M_B_CPU1_SB_DQ<1>")
	)
	(segment
		(start 48.724058 -230.041704)
		(end 48.541178 -229.858824)
		(width 0.18288)
		(layer "In4.Cu")
		(net "M_B_CPU1_SB_DQ<1>")
	)
	(segment
		(start 48.541178 -229.858824)
		(end 48.541178 -229.23373)
		(width 0.18288)
		(layer "In4.Cu")
		(net "M_B_CPU1_SB_DQ<1>")
	)
	(segment
		(start 48.358298 -229.05085)
		(end 48.041814 -229.05085)
		(width 0.18288)
		(layer "In4.Cu")
		(net "M_B_CPU1_SB_DQ<1>")
	)
	(segment
		(start 49.049178 -230.041704)
		(end 48.724058 -230.041704)
		(width 0.18288)
		(layer "In4.Cu")
		(net "M_B_CPU1_SB_DQ<1>")
	)
	(segment
		(start 88.802464 -236.27334)
		(end 88.798654 -236.271308)
		(width 0.088646)
		(layer "In4.Cu")
		(net "M_B_CPU1_SB_DQ<1>")
	)
	(segment
		(start 54.944518 -229.179374)
		(end 54.231794 -229.179374)
		(width 0.18288)
		(layer "In4.Cu")
		(net "M_B_CPU1_SB_DQ<1>")
	)
	(segment
		(start 84.545932 -236.53623)
		(end 83.064096 -236.53623)
		(width 0.088646)
		(layer "In4.Cu")
		(net "M_B_CPU1_SB_DQ<1>")
	)
	(segment
		(start 61.394848 -230.041704)
		(end 60.544964 -229.19182)
		(width 0.18288)
		(layer "In4.Cu")
		(net "M_B_CPU1_SB_DQ<1>")
	)
	(segment
		(start 55.678324 -229.91318)
		(end 54.944518 -229.179374)
		(width 0.18288)
		(layer "In4.Cu")
		(net "M_B_CPU1_SB_DQ<1>")
	)
	(segment
		(start 47.667418 -230.041704)
		(end 47.389288 -230.041704)
		(width 0.18288)
		(layer "In4.Cu")
		(net "M_B_CPU1_SB_DQ<1>")
	)
	(segment
		(start 48.541178 -229.23373)
		(end 48.358298 -229.05085)
		(width 0.18288)
		(layer "In4.Cu")
		(net "M_B_CPU1_SB_DQ<1>")
	)
	(segment
		(start 67.91833 -230.891842)
		(end 65.300098 -230.891842)
		(width 0.18288)
		(layer "In4.Cu")
		(net "M_B_CPU1_SB_DQ<1>")
	)
	(segment
		(start 65.300098 -230.891842)
		(end 64.44996 -230.041704)
		(width 0.18288)
		(layer "In4.Cu")
		(net "M_B_CPU1_SB_DQ<1>")
	)
	(segment
		(start 64.44996 -230.041704)
		(end 61.394848 -230.041704)
		(width 0.18288)
		(layer "In4.Cu")
		(net "M_B_CPU1_SB_DQ<1>")
	)
	(segment
		(start 49.414938 -229.285292)
		(end 49.232058 -229.468172)
		(width 0.18288)
		(layer "In4.Cu")
		(net "M_B_CPU1_SB_DQ<1>")
	)
	(segment
		(start 49.232058 -229.858824)
		(end 49.049178 -230.041704)
		(width 0.18288)
		(layer "In4.Cu")
		(net "M_B_CPU1_SB_DQ<1>")
	)
	(segment
		(start 84.904326 -236.273594)
		(end 84.74075 -236.341412)
		(width 0.088646)
		(layer "In4.Cu")
		(net "M_B_CPU1_SB_DQ<1>")
	)
	(segment
		(start 90.68943 -236.277658)
		(end 90.682064 -236.27334)
		(width 0.088646)
		(layer "In4.Cu")
		(net "M_B_CPU1_SB_DQ<1>")
	)
	(segment
		(start 83.064096 -236.53623)
		(end 73.562718 -236.53623)
		(width 0.18288)
		(layer "In4.Cu")
		(net "M_B_CPU1_SB_DQ<1>")
	)
	(segment
		(start 57.638188 -229.19182)
		(end 56.916828 -229.91318)
		(width 0.18288)
		(layer "In4.Cu")
		(net "M_B_CPU1_SB_DQ<1>")
	)
	(segment
		(start 84.74075 -236.341412)
		(end 84.545932 -236.53623)
		(width 0.088646)
		(layer "In4.Cu")
		(net "M_B_CPU1_SB_DQ<1>")
	)
	(segment
		(start 48.041814 -229.05085)
		(end 47.850298 -229.242366)
		(width 0.18288)
		(layer "In4.Cu")
		(net "M_B_CPU1_SB_DQ<1>")
	)
	(segment
		(start 54.231794 -229.179374)
		(end 53.57495 -229.836218)
		(width 0.18288)
		(layer "In4.Cu")
		(net "M_B_CPU1_SB_DQ<1>")
	)
	(segment
		(start 85.043264 -236.273594)
		(end 84.904326 -236.273594)
		(width 0.088646)
		(layer "In4.Cu")
		(net "M_B_CPU1_SB_DQ<1>")
	)
	(segment
		(start 49.922938 -229.468172)
		(end 49.740058 -229.285292)
		(width 0.18288)
		(layer "In4.Cu")
		(net "M_B_CPU1_SB_DQ<1>")
	)
	(segment
		(start 88.427814 -236.27334)
		(end 88.428068 -236.273594)
		(width 0.088646)
		(layer "In4.Cu")
		(net "M_B_CPU1_SB_DQ<1>")
	)
	(segment
		(start 52.918106 -229.836218)
		(end 52.71262 -230.041704)
		(width 0.18288)
		(layer "In4.Cu")
		(net "M_B_CPU1_SB_DQ<1>")
	)
	(segment
		(start 52.71262 -230.041704)
		(end 50.105818 -230.041704)
		(width 0.18288)
		(layer "In4.Cu")
		(net "M_B_CPU1_SB_DQ<1>")
	)
	(segment
		(start 60.544964 -229.19182)
		(end 57.638188 -229.19182)
		(width 0.18288)
		(layer "In4.Cu")
		(net "M_B_CPU1_SB_DQ<1>")
	)
	(segment
		(start 47.850298 -229.858824)
		(end 47.667418 -230.041704)
		(width 0.18288)
		(layer "In4.Cu")
		(net "M_B_CPU1_SB_DQ<1>")
	)
	(segment
		(start 49.232058 -229.468172)
		(end 49.232058 -229.858824)
		(width 0.18288)
		(layer "In4.Cu")
		(net "M_B_CPU1_SB_DQ<1>")
	)
	(segment
		(start 53.57495 -229.836218)
		(end 52.918106 -229.836218)
		(width 0.18288)
		(layer "In4.Cu")
		(net "M_B_CPU1_SB_DQ<1>")
	)
	(segment
		(start 49.922938 -229.858824)
		(end 49.922938 -229.468172)
		(width 0.18288)
		(layer "In4.Cu")
		(net "M_B_CPU1_SB_DQ<1>")
	)
	(segment
		(start 73.562718 -236.53623)
		(end 67.91833 -230.891842)
		(width 0.18288)
		(layer "In4.Cu")
		(net "M_B_CPU1_SB_DQ<1>")
	)
	(arc
		(start 89.737692 -236.2708)
		(mid 89.552307 -236.223162)
		(end 89.367614 -236.27334)
		(width 0.088646)
		(layer "In4.Cu")
		(net "M_B_CPU1_SB_DQ<1>")
	)
	(arc
		(start 88.428068 -236.273594)
		(mid 88.145366 -236.349336)
		(end 87.862664 -236.273594)
		(width 0.088646)
		(layer "In4.Cu")
		(net "M_B_CPU1_SB_DQ<1>")
	)
	(arc
		(start 91.247214 -236.27334)
		(mid 90.968891 -236.349099)
		(end 90.68943 -236.277658)
		(width 0.088646)
		(layer "In4.Cu")
		(net "M_B_CPU1_SB_DQ<1>")
	)
	(arc
		(start 90.677492 -236.2708)
		(mid 90.492107 -236.223162)
		(end 90.307414 -236.27334)
		(width 0.088646)
		(layer "In4.Cu")
		(net "M_B_CPU1_SB_DQ<1>")
	)
	(arc
		(start 88.798654 -236.271308)
		(mid 88.612964 -236.22323)
		(end 88.427814 -236.27334)
		(width 0.088646)
		(layer "In4.Cu")
		(net "M_B_CPU1_SB_DQ<1>")
	)
	(arc
		(start 85.608668 -236.273594)
		(mid 85.325966 -236.349336)
		(end 85.043264 -236.273594)
		(width 0.088646)
		(layer "In4.Cu")
		(net "M_B_CPU1_SB_DQ<1>")
	)
	(arc
		(start 89.367614 -236.27334)
		(mid 89.089291 -236.349099)
		(end 88.80983 -236.277658)
		(width 0.088646)
		(layer "In4.Cu")
		(net "M_B_CPU1_SB_DQ<1>")
	)
	(arc
		(start 87.488268 -236.273594)
		(mid 87.205566 -236.349336)
		(end 86.922864 -236.273594)
		(width 0.088646)
		(layer "In4.Cu")
		(net "M_B_CPU1_SB_DQ<1>")
	)
	(arc
		(start 91.904566 -235.783882)
		(mid 91.627386 -236.026843)
		(end 91.32062 -236.231176)
		(width 0.088646)
		(layer "In4.Cu")
		(net "M_B_CPU1_SB_DQ<1>")
	)
	(arc
		(start 85.983064 -236.273594)
		(mid 85.795866 -236.223451)
		(end 85.608668 -236.273594)
		(width 0.088646)
		(layer "In4.Cu")
		(net "M_B_CPU1_SB_DQ<1>")
	)
	(arc
		(start 90.307414 -236.27334)
		(mid 90.029091 -236.349099)
		(end 89.74963 -236.277658)
		(width 0.088646)
		(layer "In4.Cu")
		(net "M_B_CPU1_SB_DQ<1>")
	)
	(arc
		(start 87.862664 -236.273594)
		(mid 87.675466 -236.223451)
		(end 87.488268 -236.273594)
		(width 0.088646)
		(layer "In4.Cu")
		(net "M_B_CPU1_SB_DQ<1>")
	)
	(arc
		(start 86.548468 -236.273594)
		(mid 86.265766 -236.349336)
		(end 85.983064 -236.273594)
		(width 0.088646)
		(layer "In4.Cu")
		(net "M_B_CPU1_SB_DQ<1>")
	)
	(arc
		(start 86.922864 -236.273594)
		(mid 86.735666 -236.223451)
		(end 86.548468 -236.273594)
		(width 0.088646)
		(layer "In4.Cu")
		(net "M_B_CPU1_SB_DQ<1>")
	)
	(segment
		(start 47.882302 -210.912456)
		(end 47.753778 -211.04098)
		(width 0.20066)
		(layer "F.Cu")
		(net "M_B_CPU1_SB_DQ<19>")
	)
	(segment
		(start 49.143412 -210.916774)
		(end 48.935894 -211.124292)
		(width 0.20066)
		(layer "F.Cu")
		(net "M_B_CPU1_SB_DQ<19>")
	)
	(segment
		(start 90.494866 -228.99497)
		(end 90.494866 -228.459284)
		(width 0.20066)
		(layer "F.Cu")
		(net "M_B_CPU1_SB_DQ<19>")
	)
	(segment
		(start 44.238926 -211.042758)
		(end 44.112942 -210.916774)
		(width 0.20066)
		(layer "F.Cu")
		(net "M_B_CPU1_SB_DQ<19>")
	)
	(segment
		(start 48.935894 -211.124292)
		(end 48.489362 -211.124292)
		(width 0.20066)
		(layer "F.Cu")
		(net "M_B_CPU1_SB_DQ<19>")
	)
	(segment
		(start 90.494866 -228.459284)
		(end 90.494612 -228.45903)
		(width 0.20066)
		(layer "F.Cu")
		(net "M_B_CPU1_SB_DQ<19>")
	)
	(segment
		(start 47.60468 -211.341716)
		(end 47.060358 -211.341716)
		(width 0.20066)
		(layer "F.Cu")
		(net "M_B_CPU1_SB_DQ<19>")
	)
	(segment
		(start 44.38142 -211.35594)
		(end 44.238926 -211.213446)
		(width 0.20066)
		(layer "F.Cu")
		(net "M_B_CPU1_SB_DQ<19>")
	)
	(segment
		(start 44.735242 -211.35594)
		(end 44.38142 -211.35594)
		(width 0.20066)
		(layer "F.Cu")
		(net "M_B_CPU1_SB_DQ<19>")
	)
	(segment
		(start 47.060358 -211.341716)
		(end 44.987464 -211.341716)
		(width 0.1016)
		(layer "F.Cu")
		(net "M_B_CPU1_SB_DQ<19>")
	)
	(segment
		(start 44.987464 -211.341716)
		(end 44.749466 -211.341716)
		(width 0.101854)
		(layer "F.Cu")
		(net "M_B_CPU1_SB_DQ<19>")
	)
	(segment
		(start 51.064414 -210.916774)
		(end 49.959514 -210.916774)
		(width 0.20066)
		(layer "F.Cu")
		(net "M_B_CPU1_SB_DQ<19>")
	)
	(segment
		(start 47.753778 -211.04098)
		(end 47.753778 -211.192618)
		(width 0.20066)
		(layer "F.Cu")
		(net "M_B_CPU1_SB_DQ<19>")
	)
	(segment
		(start 44.749466 -211.341716)
		(end 44.735242 -211.35594)
		(width 0.101854)
		(layer "F.Cu")
		(net "M_B_CPU1_SB_DQ<19>")
	)
	(segment
		(start 48.277526 -210.912456)
		(end 47.882302 -210.912456)
		(width 0.20066)
		(layer "F.Cu")
		(net "M_B_CPU1_SB_DQ<19>")
	)
	(segment
		(start 49.959514 -210.916774)
		(end 49.143412 -210.916774)
		(width 0.20066)
		(layer "F.Cu")
		(net "M_B_CPU1_SB_DQ<19>")
	)
	(segment
		(start 44.112942 -210.916774)
		(end 42.415714 -210.916774)
		(width 0.20066)
		(layer "F.Cu")
		(net "M_B_CPU1_SB_DQ<19>")
	)
	(segment
		(start 48.489362 -211.124292)
		(end 48.277526 -210.912456)
		(width 0.20066)
		(layer "F.Cu")
		(net "M_B_CPU1_SB_DQ<19>")
	)
	(segment
		(start 44.238926 -211.213446)
		(end 44.238926 -211.042758)
		(width 0.20066)
		(layer "F.Cu")
		(net "M_B_CPU1_SB_DQ<19>")
	)
	(segment
		(start 47.753778 -211.192618)
		(end 47.60468 -211.341716)
		(width 0.20066)
		(layer "F.Cu")
		(net "M_B_CPU1_SB_DQ<19>")
	)
	(segment
		(start 58.331354 -210.52409)
		(end 56.582056 -210.52409)
		(width 0.18288)
		(layer "In2.Cu")
		(net "M_B_CPU1_SB_DQ<19>")
	)
	(segment
		(start 74.202798 -215.307164)
		(end 74.417682 -215.09228)
		(width 0.18288)
		(layer "In2.Cu")
		(net "M_B_CPU1_SB_DQ<19>")
	)
	(segment
		(start 73.418954 -213.820756)
		(end 73.192386 -213.594188)
		(width 0.18288)
		(layer "In2.Cu")
		(net "M_B_CPU1_SB_DQ<19>")
	)
	(segment
		(start 51.529488 -211.381848)
		(end 51.064414 -210.916774)
		(width 0.18288)
		(layer "In2.Cu")
		(net "M_B_CPU1_SB_DQ<19>")
	)
	(segment
		(start 62.788292 -209.924396)
		(end 62.507876 -209.924396)
		(width 0.18288)
		(layer "In2.Cu")
		(net "M_B_CPU1_SB_DQ<19>")
	)
	(segment
		(start 74.191114 -214.592916)
		(end 73.918318 -214.592916)
		(width 0.18288)
		(layer "In2.Cu")
		(net "M_B_CPU1_SB_DQ<19>")
	)
	(segment
		(start 86.55431 -227.159058)
		(end 86.548214 -227.155502)
		(width 0.088646)
		(layer "In2.Cu")
		(net "M_B_CPU1_SB_DQ<19>")
	)
	(segment
		(start 56.582056 -210.52409)
		(end 56.524652 -210.581494)
		(width 0.18288)
		(layer "In2.Cu")
		(net "M_B_CPU1_SB_DQ<19>")
	)
	(segment
		(start 74.417682 -214.819484)
		(end 74.191114 -214.592916)
		(width 0.18288)
		(layer "In2.Cu")
		(net "M_B_CPU1_SB_DQ<19>")
	)
	(segment
		(start 84.441538 -224.849944)
		(end 84.136738 -224.545144)
		(width 0.088646)
		(layer "In2.Cu")
		(net "M_B_CPU1_SB_DQ<19>")
	)
	(segment
		(start 67.132708 -210.154774)
		(end 66.588132 -210.69935)
		(width 0.18288)
		(layer "In2.Cu")
		(net "M_B_CPU1_SB_DQ<19>")
	)
	(segment
		(start 73.430638 -214.8078)
		(end 73.20407 -214.581232)
		(width 0.18288)
		(layer "In2.Cu")
		(net "M_B_CPU1_SB_DQ<19>")
	)
	(segment
		(start 70.42277 -211.097368)
		(end 70.42277 -210.824572)
		(width 0.18288)
		(layer "In2.Cu")
		(net "M_B_CPU1_SB_DQ<19>")
	)
	(segment
		(start 71.705978 -212.810344)
		(end 71.433182 -212.810344)
		(width 0.18288)
		(layer "In2.Cu")
		(net "M_B_CPU1_SB_DQ<19>")
	)
	(segment
		(start 59.27471 -210.78063)
		(end 58.587894 -210.78063)
		(width 0.18288)
		(layer "In2.Cu")
		(net "M_B_CPU1_SB_DQ<19>")
	)
	(segment
		(start 70.70725 -211.811616)
		(end 70.434454 -211.811616)
		(width 0.18288)
		(layer "In2.Cu")
		(net "M_B_CPU1_SB_DQ<19>")
	)
	(segment
		(start 72.420226 -213.094824)
		(end 72.420226 -212.822028)
		(width 0.18288)
		(layer "In2.Cu")
		(net "M_B_CPU1_SB_DQ<19>")
	)
	(segment
		(start 86.361016 -226.83978)
		(end 86.361016 -226.821238)
		(width 0.088646)
		(layer "In2.Cu")
		(net "M_B_CPU1_SB_DQ<19>")
	)
	(segment
		(start 84.441538 -225.319082)
		(end 84.441538 -224.849944)
		(width 0.088646)
		(layer "In2.Cu")
		(net "M_B_CPU1_SB_DQ<19>")
	)
	(segment
		(start 73.918318 -214.592916)
		(end 73.703434 -214.8078)
		(width 0.18288)
		(layer "In2.Cu")
		(net "M_B_CPU1_SB_DQ<19>")
	)
	(segment
		(start 71.206614 -212.583776)
		(end 71.206614 -212.31098)
		(width 0.18288)
		(layer "In2.Cu")
		(net "M_B_CPU1_SB_DQ<19>")
	)
	(segment
		(start 86.078568 -226.341686)
		(end 86.069678 -226.336606)
		(width 0.088646)
		(layer "In2.Cu")
		(net "M_B_CPU1_SB_DQ<19>")
	)
	(segment
		(start 73.192386 -213.594188)
		(end 72.91959 -213.594188)
		(width 0.18288)
		(layer "In2.Cu")
		(net "M_B_CPU1_SB_DQ<19>")
	)
	(segment
		(start 71.920862 -212.59546)
		(end 71.705978 -212.810344)
		(width 0.18288)
		(layer "In2.Cu")
		(net "M_B_CPU1_SB_DQ<19>")
	)
	(segment
		(start 71.19493 -211.596732)
		(end 70.922134 -211.596732)
		(width 0.18288)
		(layer "In2.Cu")
		(net "M_B_CPU1_SB_DQ<19>")
	)
	(segment
		(start 56.524652 -210.581494)
		(end 55.681372 -210.581494)
		(width 0.18288)
		(layer "In2.Cu")
		(net "M_B_CPU1_SB_DQ<19>")
	)
	(segment
		(start 71.206614 -212.31098)
		(end 71.421498 -212.096096)
		(width 0.18288)
		(layer "In2.Cu")
		(net "M_B_CPU1_SB_DQ<19>")
	)
	(segment
		(start 66.282062 -210.69935)
		(end 66.106802 -210.52409)
		(width 0.18288)
		(layer "In2.Cu")
		(net "M_B_CPU1_SB_DQ<19>")
	)
	(segment
		(start 62.507876 -209.924396)
		(end 61.947298 -210.484974)
		(width 0.18288)
		(layer "In2.Cu")
		(net "M_B_CPU1_SB_DQ<19>")
	)
	(segment
		(start 85.057996 -225.51898)
		(end 85.043264 -225.527616)
		(width 0.088646)
		(layer "In2.Cu")
		(net "M_B_CPU1_SB_DQ<19>")
	)
	(segment
		(start 72.420226 -212.822028)
		(end 72.193658 -212.59546)
		(width 0.18288)
		(layer "In2.Cu")
		(net "M_B_CPU1_SB_DQ<19>")
	)
	(segment
		(start 63.902082 -210.774026)
		(end 63.174372 -210.774026)
		(width 0.18288)
		(layer "In2.Cu")
		(net "M_B_CPU1_SB_DQ<19>")
	)
	(segment
		(start 75.173586 -215.581992)
		(end 74.98334 -215.581992)
		(width 0.18288)
		(layer "In2.Cu")
		(net "M_B_CPU1_SB_DQ<19>")
	)
	(segment
		(start 70.207886 -211.585048)
		(end 70.207886 -211.312252)
		(width 0.18288)
		(layer "In2.Cu")
		(net "M_B_CPU1_SB_DQ<19>")
	)
	(segment
		(start 61.947298 -210.484974)
		(end 59.570366 -210.484974)
		(width 0.18288)
		(layer "In2.Cu")
		(net "M_B_CPU1_SB_DQ<19>")
	)
	(segment
		(start 72.205342 -213.582504)
		(end 72.205342 -213.309708)
		(width 0.18288)
		(layer "In2.Cu")
		(net "M_B_CPU1_SB_DQ<19>")
	)
	(segment
		(start 55.681372 -210.581494)
		(end 54.881018 -211.381848)
		(width 0.18288)
		(layer "In2.Cu")
		(net "M_B_CPU1_SB_DQ<19>")
	)
	(segment
		(start 62.981332 -210.117436)
		(end 62.788292 -209.924396)
		(width 0.18288)
		(layer "In2.Cu")
		(net "M_B_CPU1_SB_DQ<19>")
	)
	(segment
		(start 66.588132 -210.69935)
		(end 66.282062 -210.69935)
		(width 0.18288)
		(layer "In2.Cu")
		(net "M_B_CPU1_SB_DQ<19>")
	)
	(segment
		(start 73.20407 -214.308436)
		(end 73.418954 -214.093552)
		(width 0.18288)
		(layer "In2.Cu")
		(net "M_B_CPU1_SB_DQ<19>")
	)
	(segment
		(start 73.703434 -214.8078)
		(end 73.430638 -214.8078)
		(width 0.18288)
		(layer "In2.Cu")
		(net "M_B_CPU1_SB_DQ<19>")
	)
	(segment
		(start 69.580506 -210.940904)
		(end 69.026278 -210.940904)
		(width 0.18288)
		(layer "In2.Cu")
		(net "M_B_CPU1_SB_DQ<19>")
	)
	(segment
		(start 74.417682 -215.09228)
		(end 74.417682 -214.819484)
		(width 0.18288)
		(layer "In2.Cu")
		(net "M_B_CPU1_SB_DQ<19>")
	)
	(segment
		(start 66.106802 -210.52409)
		(end 64.152018 -210.52409)
		(width 0.18288)
		(layer "In2.Cu")
		(net "M_B_CPU1_SB_DQ<19>")
	)
	(segment
		(start 87.30488 -228.134672)
		(end 87.018114 -227.969318)
		(width 0.088646)
		(layer "In2.Cu")
		(net "M_B_CPU1_SB_DQ<19>")
	)
	(segment
		(start 72.43191 -213.809072)
		(end 72.205342 -213.582504)
		(width 0.18288)
		(layer "In2.Cu")
		(net "M_B_CPU1_SB_DQ<19>")
	)
	(segment
		(start 88.428068 -228.134672)
		(end 88.427814 -228.134672)
		(width 0.088646)
		(layer "In2.Cu")
		(net "M_B_CPU1_SB_DQ<19>")
	)
	(segment
		(start 71.433182 -212.810344)
		(end 71.206614 -212.583776)
		(width 0.18288)
		(layer "In2.Cu")
		(net "M_B_CPU1_SB_DQ<19>")
	)
	(segment
		(start 90.14079 -228.364288)
		(end 89.736422 -228.131116)
		(width 0.088646)
		(layer "In2.Cu")
		(net "M_B_CPU1_SB_DQ<19>")
	)
	(segment
		(start 84.136738 -224.545144)
		(end 75.173586 -215.581992)
		(width 0.18288)
		(layer "In2.Cu")
		(net "M_B_CPU1_SB_DQ<19>")
	)
	(segment
		(start 71.421498 -212.096096)
		(end 71.421498 -211.8233)
		(width 0.18288)
		(layer "In2.Cu")
		(net "M_B_CPU1_SB_DQ<19>")
	)
	(segment
		(start 63.174372 -210.774026)
		(end 62.981332 -210.580986)
		(width 0.18288)
		(layer "In2.Cu")
		(net "M_B_CPU1_SB_DQ<19>")
	)
	(segment
		(start 74.98334 -215.581992)
		(end 74.73061 -215.834722)
		(width 0.18288)
		(layer "In2.Cu")
		(net "M_B_CPU1_SB_DQ<19>")
	)
	(segment
		(start 72.91959 -213.594188)
		(end 72.704706 -213.809072)
		(width 0.18288)
		(layer "In2.Cu")
		(net "M_B_CPU1_SB_DQ<19>")
	)
	(segment
		(start 62.981332 -210.580986)
		(end 62.981332 -210.117436)
		(width 0.18288)
		(layer "In2.Cu")
		(net "M_B_CPU1_SB_DQ<19>")
	)
	(segment
		(start 70.922134 -211.596732)
		(end 70.70725 -211.811616)
		(width 0.18288)
		(layer "In2.Cu")
		(net "M_B_CPU1_SB_DQ<19>")
	)
	(segment
		(start 58.587894 -210.78063)
		(end 58.331354 -210.52409)
		(width 0.18288)
		(layer "In2.Cu")
		(net "M_B_CPU1_SB_DQ<19>")
	)
	(segment
		(start 69.026278 -210.940904)
		(end 68.240148 -210.154774)
		(width 0.18288)
		(layer "In2.Cu")
		(net "M_B_CPU1_SB_DQ<19>")
	)
	(segment
		(start 85.891116 -226.017328)
		(end 85.891116 -226.003104)
		(width 0.088646)
		(layer "In2.Cu")
		(net "M_B_CPU1_SB_DQ<19>")
	)
	(segment
		(start 74.73061 -215.834722)
		(end 74.45756 -215.834722)
		(width 0.18288)
		(layer "In2.Cu")
		(net "M_B_CPU1_SB_DQ<19>")
	)
	(segment
		(start 64.152018 -210.52409)
		(end 63.902082 -210.774026)
		(width 0.18288)
		(layer "In2.Cu")
		(net "M_B_CPU1_SB_DQ<19>")
	)
	(segment
		(start 70.196202 -210.598004)
		(end 69.923406 -210.598004)
		(width 0.18288)
		(layer "In2.Cu")
		(net "M_B_CPU1_SB_DQ<19>")
	)
	(segment
		(start 74.202798 -215.57996)
		(end 74.202798 -215.307164)
		(width 0.18288)
		(layer "In2.Cu")
		(net "M_B_CPU1_SB_DQ<19>")
	)
	(segment
		(start 68.240148 -210.154774)
		(end 67.132708 -210.154774)
		(width 0.18288)
		(layer "In2.Cu")
		(net "M_B_CPU1_SB_DQ<19>")
	)
	(segment
		(start 54.881018 -211.381848)
		(end 51.529488 -211.381848)
		(width 0.18288)
		(layer "In2.Cu")
		(net "M_B_CPU1_SB_DQ<19>")
	)
	(segment
		(start 59.570366 -210.484974)
		(end 59.27471 -210.78063)
		(width 0.18288)
		(layer "In2.Cu")
		(net "M_B_CPU1_SB_DQ<19>")
	)
	(segment
		(start 86.830916 -227.645214)
		(end 86.830916 -227.64496)
		(width 0.088646)
		(layer "In2.Cu")
		(net "M_B_CPU1_SB_DQ<19>")
	)
	(segment
		(start 70.207886 -211.312252)
		(end 70.42277 -211.097368)
		(width 0.18288)
		(layer "In2.Cu")
		(net "M_B_CPU1_SB_DQ<19>")
	)
	(segment
		(start 69.923406 -210.598004)
		(end 69.580506 -210.940904)
		(width 0.18288)
		(layer "In2.Cu")
		(net "M_B_CPU1_SB_DQ<19>")
	)
	(segment
		(start 72.205342 -213.309708)
		(end 72.420226 -213.094824)
		(width 0.18288)
		(layer "In2.Cu")
		(net "M_B_CPU1_SB_DQ<19>")
	)
	(segment
		(start 87.862664 -228.134672)
		(end 87.86241 -228.134672)
		(width 0.088646)
		(layer "In2.Cu")
		(net "M_B_CPU1_SB_DQ<19>")
	)
	(segment
		(start 73.418954 -214.093552)
		(end 73.418954 -213.820756)
		(width 0.18288)
		(layer "In2.Cu")
		(net "M_B_CPU1_SB_DQ<19>")
	)
	(segment
		(start 70.434454 -211.811616)
		(end 70.207886 -211.585048)
		(width 0.18288)
		(layer "In2.Cu")
		(net "M_B_CPU1_SB_DQ<19>")
	)
	(segment
		(start 73.20407 -214.581232)
		(end 73.20407 -214.308436)
		(width 0.18288)
		(layer "In2.Cu")
		(net "M_B_CPU1_SB_DQ<19>")
	)
	(segment
		(start 72.704706 -213.809072)
		(end 72.43191 -213.809072)
		(width 0.18288)
		(layer "In2.Cu")
		(net "M_B_CPU1_SB_DQ<19>")
	)
	(segment
		(start 70.42277 -210.824572)
		(end 70.196202 -210.598004)
		(width 0.18288)
		(layer "In2.Cu")
		(net "M_B_CPU1_SB_DQ<19>")
	)
	(segment
		(start 71.421498 -211.8233)
		(end 71.19493 -211.596732)
		(width 0.18288)
		(layer "In2.Cu")
		(net "M_B_CPU1_SB_DQ<19>")
	)
	(segment
		(start 88.427814 -228.134672)
		(end 88.4174 -228.140768)
		(width 0.088646)
		(layer "In2.Cu")
		(net "M_B_CPU1_SB_DQ<19>")
	)
	(segment
		(start 74.45756 -215.834722)
		(end 74.202798 -215.57996)
		(width 0.18288)
		(layer "In2.Cu")
		(net "M_B_CPU1_SB_DQ<19>")
	)
	(segment
		(start 72.193658 -212.59546)
		(end 71.920862 -212.59546)
		(width 0.18288)
		(layer "In2.Cu")
		(net "M_B_CPU1_SB_DQ<19>")
	)
	(segment
		(start 84.590636 -225.468688)
		(end 84.441538 -225.319082)
		(width 0.088646)
		(layer "In2.Cu")
		(net "M_B_CPU1_SB_DQ<19>")
	)
	(arc
		(start 85.608668 -225.527616)
		(mid 85.334439 -225.451691)
		(end 85.057996 -225.51898)
		(width 0.088646)
		(layer "In2.Cu")
		(net "M_B_CPU1_SB_DQ<19>")
	)
	(arc
		(start 86.069678 -226.336606)
		(mid 85.938764 -226.200246)
		(end 85.891116 -226.017328)
		(width 0.088646)
		(layer "In2.Cu")
		(net "M_B_CPU1_SB_DQ<19>")
	)
	(arc
		(start 88.802718 -228.134672)
		(mid 88.615376 -228.084436)
		(end 88.428068 -228.134672)
		(width 0.088646)
		(layer "In2.Cu")
		(net "M_B_CPU1_SB_DQ<19>")
	)
	(arc
		(start 88.4174 -228.140768)
		(mid 88.139222 -228.21046)
		(end 87.862664 -228.134672)
		(width 0.088646)
		(layer "In2.Cu")
		(net "M_B_CPU1_SB_DQ<19>")
	)
	(arc
		(start 85.891116 -226.003104)
		(mid 85.811975 -225.728481)
		(end 85.608668 -225.527616)
		(width 0.088646)
		(layer "In2.Cu")
		(net "M_B_CPU1_SB_DQ<19>")
	)
	(arc
		(start 87.018114 -227.969318)
		(mid 86.881069 -227.832358)
		(end 86.830916 -227.645214)
		(width 0.088646)
		(layer "In2.Cu")
		(net "M_B_CPU1_SB_DQ<19>")
	)
	(arc
		(start 84.668868 -225.527616)
		(mid 84.62781 -225.500729)
		(end 84.590636 -225.468688)
		(width 0.088646)
		(layer "In2.Cu")
		(net "M_B_CPU1_SB_DQ<19>")
	)
	(arc
		(start 89.367614 -228.134418)
		(mid 89.085195 -228.210228)
		(end 88.802718 -228.134672)
		(width 0.088646)
		(layer "In2.Cu")
		(net "M_B_CPU1_SB_DQ<19>")
	)
	(arc
		(start 87.488268 -228.134672)
		(mid 87.396574 -228.159251)
		(end 87.30488 -228.134672)
		(width 0.088646)
		(layer "In2.Cu")
		(net "M_B_CPU1_SB_DQ<19>")
	)
	(arc
		(start 86.830916 -227.64496)
		(mid 86.756925 -227.365394)
		(end 86.55431 -227.159058)
		(width 0.088646)
		(layer "In2.Cu")
		(net "M_B_CPU1_SB_DQ<19>")
	)
	(arc
		(start 89.736422 -228.131116)
		(mid 89.551567 -228.084198)
		(end 89.367614 -228.134418)
		(width 0.088646)
		(layer "In2.Cu")
		(net "M_B_CPU1_SB_DQ<19>")
	)
	(arc
		(start 90.494612 -228.45903)
		(mid 90.311495 -228.434854)
		(end 90.14079 -228.364288)
		(width 0.088646)
		(layer "In2.Cu")
		(net "M_B_CPU1_SB_DQ<19>")
	)
	(arc
		(start 86.548214 -227.155502)
		(mid 86.413281 -227.022148)
		(end 86.361016 -226.83978)
		(width 0.088646)
		(layer "In2.Cu")
		(net "M_B_CPU1_SB_DQ<19>")
	)
	(arc
		(start 86.361016 -226.821238)
		(mid 86.282905 -226.544289)
		(end 86.078568 -226.341686)
		(width 0.088646)
		(layer "In2.Cu")
		(net "M_B_CPU1_SB_DQ<19>")
	)
	(arc
		(start 85.043264 -225.527616)
		(mid 84.856066 -225.577759)
		(end 84.668868 -225.527616)
		(width 0.088646)
		(layer "In2.Cu")
		(net "M_B_CPU1_SB_DQ<19>")
	)
	(arc
		(start 87.86241 -228.134672)
		(mid 87.675356 -228.084622)
		(end 87.488268 -228.134672)
		(width 0.088646)
		(layer "In2.Cu")
		(net "M_B_CPU1_SB_DQ<19>")
	)
	(segment
		(start 44.745402 -212.191854)
		(end 44.735242 -212.181694)
		(width 0.101854)
		(layer "F.Cu")
		(net "M_B_CPU1_SB_DQ<18>")
	)
	(segment
		(start 48.432974 -212.828632)
		(end 48.004476 -212.828632)
		(width 0.20066)
		(layer "F.Cu")
		(net "M_B_CPU1_SB_DQ<18>")
	)
	(segment
		(start 43.99788 -212.181694)
		(end 43.562778 -212.616796)
		(width 0.20066)
		(layer "F.Cu")
		(net "M_B_CPU1_SB_DQ<18>")
	)
	(segment
		(start 90.024712 -229.808786)
		(end 90.024966 -229.808532)
		(width 0.20066)
		(layer "F.Cu")
		(net "M_B_CPU1_SB_DQ<18>")
	)
	(segment
		(start 90.024966 -229.808532)
		(end 90.024966 -229.272846)
		(width 0.20066)
		(layer "F.Cu")
		(net "M_B_CPU1_SB_DQ<18>")
	)
	(segment
		(start 45.000418 -212.191854)
		(end 44.745402 -212.191854)
		(width 0.101854)
		(layer "F.Cu")
		(net "M_B_CPU1_SB_DQ<18>")
	)
	(segment
		(start 47.83709 -212.335618)
		(end 47.693326 -212.191854)
		(width 0.20066)
		(layer "F.Cu")
		(net "M_B_CPU1_SB_DQ<18>")
	)
	(segment
		(start 48.64481 -212.616796)
		(end 48.432974 -212.828632)
		(width 0.20066)
		(layer "F.Cu")
		(net "M_B_CPU1_SB_DQ<18>")
	)
	(segment
		(start 47.693326 -212.191854)
		(end 47.060358 -212.191854)
		(width 0.20066)
		(layer "F.Cu")
		(net "M_B_CPU1_SB_DQ<18>")
	)
	(segment
		(start 51.064414 -212.616796)
		(end 49.959514 -212.616796)
		(width 0.20066)
		(layer "F.Cu")
		(net "M_B_CPU1_SB_DQ<18>")
	)
	(segment
		(start 47.83709 -212.661246)
		(end 47.83709 -212.335618)
		(width 0.20066)
		(layer "F.Cu")
		(net "M_B_CPU1_SB_DQ<18>")
	)
	(segment
		(start 43.562778 -212.616796)
		(end 42.415714 -212.616796)
		(width 0.20066)
		(layer "F.Cu")
		(net "M_B_CPU1_SB_DQ<18>")
	)
	(segment
		(start 44.735242 -212.181694)
		(end 43.99788 -212.181694)
		(width 0.20066)
		(layer "F.Cu")
		(net "M_B_CPU1_SB_DQ<18>")
	)
	(segment
		(start 48.004476 -212.828632)
		(end 47.83709 -212.661246)
		(width 0.20066)
		(layer "F.Cu")
		(net "M_B_CPU1_SB_DQ<18>")
	)
	(segment
		(start 49.959514 -212.616796)
		(end 48.64481 -212.616796)
		(width 0.20066)
		(layer "F.Cu")
		(net "M_B_CPU1_SB_DQ<18>")
	)
	(segment
		(start 47.060358 -212.191854)
		(end 45.000418 -212.191854)
		(width 0.1016)
		(layer "F.Cu")
		(net "M_B_CPU1_SB_DQ<18>")
	)
	(segment
		(start 76.22667 -218.421458)
		(end 76.050902 -218.596972)
		(width 0.18288)
		(layer "In2.Cu")
		(net "M_B_CPU1_SB_DQ<18>")
	)
	(segment
		(start 80.045814 -222.591884)
		(end 79.773018 -222.591884)
		(width 0.18288)
		(layer "In2.Cu")
		(net "M_B_CPU1_SB_DQ<18>")
	)
	(segment
		(start 78.72349 -220.645482)
		(end 78.496922 -220.418914)
		(width 0.18288)
		(layer "In2.Cu")
		(net "M_B_CPU1_SB_DQ<18>")
	)
	(segment
		(start 79.722218 -221.917006)
		(end 79.722218 -221.64421)
		(width 0.18288)
		(layer "In2.Cu")
		(net "M_B_CPU1_SB_DQ<18>")
	)
	(segment
		(start 58.423048 -212.246972)
		(end 58.105548 -211.929472)
		(width 0.18288)
		(layer "In2.Cu")
		(net "M_B_CPU1_SB_DQ<18>")
	)
	(segment
		(start 79.773018 -222.591884)
		(end 79.54645 -222.365316)
		(width 0.18288)
		(layer "In2.Cu")
		(net "M_B_CPU1_SB_DQ<18>")
	)
	(segment
		(start 51.663092 -212.616796)
		(end 51.064414 -212.616796)
		(width 0.18288)
		(layer "In2.Cu")
		(net "M_B_CPU1_SB_DQ<18>")
	)
	(segment
		(start 75.551538 -218.097608)
		(end 75.727306 -217.922094)
		(width 0.18288)
		(layer "In2.Cu")
		(net "M_B_CPU1_SB_DQ<18>")
	)
	(segment
		(start 81.719674 -223.914462)
		(end 81.719674 -223.641666)
		(width 0.18288)
		(layer "In2.Cu")
		(net "M_B_CPU1_SB_DQ<18>")
	)
	(segment
		(start 77.04963 -219.5957)
		(end 76.776834 -219.5957)
		(width 0.18288)
		(layer "In2.Cu")
		(net "M_B_CPU1_SB_DQ<18>")
	)
	(segment
		(start 78.547722 -221.366588)
		(end 78.547722 -221.093792)
		(width 0.18288)
		(layer "In2.Cu")
		(net "M_B_CPU1_SB_DQ<18>")
	)
	(segment
		(start 76.726034 -218.648026)
		(end 76.499466 -218.421458)
		(width 0.18288)
		(layer "In2.Cu")
		(net "M_B_CPU1_SB_DQ<18>")
	)
	(segment
		(start 82.718402 -224.640394)
		(end 82.491834 -224.413826)
		(width 0.18288)
		(layer "In2.Cu")
		(net "M_B_CPU1_SB_DQ<18>")
	)
	(segment
		(start 88.902286 -228.945694)
		(end 88.897968 -228.948488)
		(width 0.088646)
		(layer "In2.Cu")
		(net "M_B_CPU1_SB_DQ<18>")
	)
	(segment
		(start 89.868248 -229.253796)
		(end 89.666064 -229.169214)
		(width 0.088646)
		(layer "In2.Cu")
		(net "M_B_CPU1_SB_DQ<18>")
	)
	(segment
		(start 74.779378 -217.598244)
		(end 69.301614 -212.12048)
		(width 0.18288)
		(layer "In2.Cu")
		(net "M_B_CPU1_SB_DQ<18>")
	)
	(segment
		(start 64.450214 -211.923884)
		(end 64.137794 -212.236304)
		(width 0.18288)
		(layer "In2.Cu")
		(net "M_B_CPU1_SB_DQ<18>")
	)
	(segment
		(start 76.499466 -218.421458)
		(end 76.22667 -218.421458)
		(width 0.18288)
		(layer "In2.Cu")
		(net "M_B_CPU1_SB_DQ<18>")
	)
	(segment
		(start 75.778106 -218.596972)
		(end 75.551538 -218.370404)
		(width 0.18288)
		(layer "In2.Cu")
		(net "M_B_CPU1_SB_DQ<18>")
	)
	(segment
		(start 81.719674 -223.641666)
		(end 81.493106 -223.415098)
		(width 0.18288)
		(layer "In2.Cu")
		(net "M_B_CPU1_SB_DQ<18>")
	)
	(segment
		(start 77.225398 -219.420186)
		(end 77.04963 -219.5957)
		(width 0.18288)
		(layer "In2.Cu")
		(net "M_B_CPU1_SB_DQ<18>")
	)
	(segment
		(start 80.720946 -222.915734)
		(end 80.720946 -222.642938)
		(width 0.18288)
		(layer "In2.Cu")
		(net "M_B_CPU1_SB_DQ<18>")
	)
	(segment
		(start 90.024966 -229.272846)
		(end 89.96553 -229.272846)
		(width 0.088646)
		(layer "In2.Cu")
		(net "M_B_CPU1_SB_DQ<18>")
	)
	(segment
		(start 85.150706 -226.348798)
		(end 85.138514 -226.341686)
		(width 0.088646)
		(layer "In2.Cu")
		(net "M_B_CPU1_SB_DQ<18>")
	)
	(segment
		(start 79.222854 -221.417642)
		(end 79.047086 -221.593156)
		(width 0.18288)
		(layer "In2.Cu")
		(net "M_B_CPU1_SB_DQ<18>")
	)
	(segment
		(start 64.137794 -212.236304)
		(end 63.505842 -212.236304)
		(width 0.18288)
		(layer "In2.Cu")
		(net "M_B_CPU1_SB_DQ<18>")
	)
	(segment
		(start 60.240926 -212.323172)
		(end 60.027566 -212.109812)
		(width 0.18288)
		(layer "In2.Cu")
		(net "M_B_CPU1_SB_DQ<18>")
	)
	(segment
		(start 82.219038 -224.413826)
		(end 82.04327 -224.58934)
		(width 0.18288)
		(layer "In2.Cu")
		(net "M_B_CPU1_SB_DQ<18>")
	)
	(segment
		(start 75.227942 -217.42273)
		(end 75.052174 -217.598244)
		(width 0.18288)
		(layer "In2.Cu")
		(net "M_B_CPU1_SB_DQ<18>")
	)
	(segment
		(start 78.048358 -220.594428)
		(end 77.775562 -220.594428)
		(width 0.18288)
		(layer "In2.Cu")
		(net "M_B_CPU1_SB_DQ<18>")
	)
	(segment
		(start 89.586562 -229.129844)
		(end 89.272364 -228.948234)
		(width 0.088646)
		(layer "In2.Cu")
		(net "M_B_CPU1_SB_DQ<18>")
	)
	(segment
		(start 76.726034 -218.920822)
		(end 76.726034 -218.648026)
		(width 0.18288)
		(layer "In2.Cu")
		(net "M_B_CPU1_SB_DQ<18>")
	)
	(segment
		(start 82.718402 -224.91319)
		(end 82.718402 -224.640394)
		(width 0.18288)
		(layer "In2.Cu")
		(net "M_B_CPU1_SB_DQ<18>")
	)
	(segment
		(start 75.727306 -217.922094)
		(end 75.727306 -217.649298)
		(width 0.18288)
		(layer "In2.Cu")
		(net "M_B_CPU1_SB_DQ<18>")
	)
	(segment
		(start 75.500738 -217.42273)
		(end 75.227942 -217.42273)
		(width 0.18288)
		(layer "In2.Cu")
		(net "M_B_CPU1_SB_DQ<18>")
	)
	(segment
		(start 75.551538 -218.370404)
		(end 75.551538 -218.097608)
		(width 0.18288)
		(layer "In2.Cu")
		(net "M_B_CPU1_SB_DQ<18>")
	)
	(segment
		(start 86.361016 -228.45903)
		(end 86.361016 -228.440488)
		(width 0.088646)
		(layer "In2.Cu")
		(net "M_B_CPU1_SB_DQ<18>")
	)
	(segment
		(start 69.301614 -212.12048)
		(end 66.529712 -212.12048)
		(width 0.18288)
		(layer "In2.Cu")
		(net "M_B_CPU1_SB_DQ<18>")
	)
	(segment
		(start 86.548468 -228.783388)
		(end 86.548214 -228.783134)
		(width 0.088646)
		(layer "In2.Cu")
		(net "M_B_CPU1_SB_DQ<18>")
	)
	(segment
		(start 79.49565 -221.417642)
		(end 79.222854 -221.417642)
		(width 0.18288)
		(layer "In2.Cu")
		(net "M_B_CPU1_SB_DQ<18>")
	)
	(segment
		(start 80.720946 -222.642938)
		(end 80.494378 -222.41637)
		(width 0.18288)
		(layer "In2.Cu")
		(net "M_B_CPU1_SB_DQ<18>")
	)
	(segment
		(start 76.776834 -219.5957)
		(end 76.550266 -219.369132)
		(width 0.18288)
		(layer "In2.Cu")
		(net "M_B_CPU1_SB_DQ<18>")
	)
	(segment
		(start 77.548994 -220.095064)
		(end 77.724762 -219.91955)
		(width 0.18288)
		(layer "In2.Cu")
		(net "M_B_CPU1_SB_DQ<18>")
	)
	(segment
		(start 77.724762 -219.646754)
		(end 77.498194 -219.420186)
		(width 0.18288)
		(layer "In2.Cu")
		(net "M_B_CPU1_SB_DQ<18>")
	)
	(segment
		(start 81.543906 -224.089976)
		(end 81.719674 -223.914462)
		(width 0.18288)
		(layer "In2.Cu")
		(net "M_B_CPU1_SB_DQ<18>")
	)
	(segment
		(start 63.33363 -212.064092)
		(end 61.831982 -212.064092)
		(width 0.18288)
		(layer "In2.Cu")
		(net "M_B_CPU1_SB_DQ<18>")
	)
	(segment
		(start 54.696614 -213.092792)
		(end 52.139088 -213.092792)
		(width 0.18288)
		(layer "In2.Cu")
		(net "M_B_CPU1_SB_DQ<18>")
	)
	(segment
		(start 81.044542 -223.590612)
		(end 80.771746 -223.590612)
		(width 0.18288)
		(layer "In2.Cu")
		(net "M_B_CPU1_SB_DQ<18>")
	)
	(segment
		(start 83.122516 -225.941382)
		(end 82.542634 -225.3615)
		(width 0.18288)
		(layer "In2.Cu")
		(net "M_B_CPU1_SB_DQ<18>")
	)
	(segment
		(start 65.62979 -211.923884)
		(end 64.450214 -211.923884)
		(width 0.18288)
		(layer "In2.Cu")
		(net "M_B_CPU1_SB_DQ<18>")
	)
	(segment
		(start 66.413888 -212.236304)
		(end 65.94221 -212.236304)
		(width 0.18288)
		(layer "In2.Cu")
		(net "M_B_CPU1_SB_DQ<18>")
	)
	(segment
		(start 63.505842 -212.236304)
		(end 63.33363 -212.064092)
		(width 0.18288)
		(layer "In2.Cu")
		(net "M_B_CPU1_SB_DQ<18>")
	)
	(segment
		(start 80.494378 -222.41637)
		(end 80.221582 -222.41637)
		(width 0.18288)
		(layer "In2.Cu")
		(net "M_B_CPU1_SB_DQ<18>")
	)
	(segment
		(start 60.027566 -212.109812)
		(end 59.365642 -212.109812)
		(width 0.18288)
		(layer "In2.Cu")
		(net "M_B_CPU1_SB_DQ<18>")
	)
	(segment
		(start 76.050902 -218.596972)
		(end 75.778106 -218.596972)
		(width 0.18288)
		(layer "In2.Cu")
		(net "M_B_CPU1_SB_DQ<18>")
	)
	(segment
		(start 81.770474 -224.58934)
		(end 81.543906 -224.362772)
		(width 0.18288)
		(layer "In2.Cu")
		(net "M_B_CPU1_SB_DQ<18>")
	)
	(segment
		(start 81.22031 -223.415098)
		(end 81.044542 -223.590612)
		(width 0.18288)
		(layer "In2.Cu")
		(net "M_B_CPU1_SB_DQ<18>")
	)
	(segment
		(start 61.572902 -212.323172)
		(end 60.240926 -212.323172)
		(width 0.18288)
		(layer "In2.Cu")
		(net "M_B_CPU1_SB_DQ<18>")
	)
	(segment
		(start 66.529712 -212.12048)
		(end 66.413888 -212.236304)
		(width 0.18288)
		(layer "In2.Cu")
		(net "M_B_CPU1_SB_DQ<18>")
	)
	(segment
		(start 81.543906 -224.362772)
		(end 81.543906 -224.089976)
		(width 0.18288)
		(layer "In2.Cu")
		(net "M_B_CPU1_SB_DQ<18>")
	)
	(segment
		(start 82.542634 -225.3615)
		(end 82.542634 -225.088704)
		(width 0.18288)
		(layer "In2.Cu")
		(net "M_B_CPU1_SB_DQ<18>")
	)
	(segment
		(start 78.547722 -221.093792)
		(end 78.72349 -220.918278)
		(width 0.18288)
		(layer "In2.Cu")
		(net "M_B_CPU1_SB_DQ<18>")
	)
	(segment
		(start 76.550266 -219.369132)
		(end 76.550266 -219.096336)
		(width 0.18288)
		(layer "In2.Cu")
		(net "M_B_CPU1_SB_DQ<18>")
	)
	(segment
		(start 77.724762 -219.91955)
		(end 77.724762 -219.646754)
		(width 0.18288)
		(layer "In2.Cu")
		(net "M_B_CPU1_SB_DQ<18>")
	)
	(segment
		(start 80.771746 -223.590612)
		(end 80.545178 -223.364044)
		(width 0.18288)
		(layer "In2.Cu")
		(net "M_B_CPU1_SB_DQ<18>")
	)
	(segment
		(start 59.365642 -212.109812)
		(end 59.228482 -212.246972)
		(width 0.18288)
		(layer "In2.Cu")
		(net "M_B_CPU1_SB_DQ<18>")
	)
	(segment
		(start 85.608668 -227.155502)
		(end 85.599778 -227.150422)
		(width 0.088646)
		(layer "In2.Cu")
		(net "M_B_CPU1_SB_DQ<18>")
	)
	(segment
		(start 80.545178 -223.364044)
		(end 80.545178 -223.091248)
		(width 0.18288)
		(layer "In2.Cu")
		(net "M_B_CPU1_SB_DQ<18>")
	)
	(segment
		(start 82.491834 -224.413826)
		(end 82.219038 -224.413826)
		(width 0.18288)
		(layer "In2.Cu")
		(net "M_B_CPU1_SB_DQ<18>")
	)
	(segment
		(start 86.078568 -227.969318)
		(end 86.069678 -227.964238)
		(width 0.088646)
		(layer "In2.Cu")
		(net "M_B_CPU1_SB_DQ<18>")
	)
	(segment
		(start 86.834472 -228.948488)
		(end 86.548468 -228.783388)
		(width 0.088646)
		(layer "In2.Cu")
		(net "M_B_CPU1_SB_DQ<18>")
	)
	(segment
		(start 76.550266 -219.096336)
		(end 76.726034 -218.920822)
		(width 0.18288)
		(layer "In2.Cu")
		(net "M_B_CPU1_SB_DQ<18>")
	)
	(segment
		(start 77.548994 -220.36786)
		(end 77.548994 -220.095064)
		(width 0.18288)
		(layer "In2.Cu")
		(net "M_B_CPU1_SB_DQ<18>")
	)
	(segment
		(start 82.542634 -225.088704)
		(end 82.718402 -224.91319)
		(width 0.18288)
		(layer "In2.Cu")
		(net "M_B_CPU1_SB_DQ<18>")
	)
	(segment
		(start 52.139088 -213.092792)
		(end 51.663092 -212.616796)
		(width 0.18288)
		(layer "In2.Cu")
		(net "M_B_CPU1_SB_DQ<18>")
	)
	(segment
		(start 58.105548 -211.929472)
		(end 56.914542 -211.929472)
		(width 0.18288)
		(layer "In2.Cu")
		(net "M_B_CPU1_SB_DQ<18>")
	)
	(segment
		(start 79.722218 -221.64421)
		(end 79.49565 -221.417642)
		(width 0.18288)
		(layer "In2.Cu")
		(net "M_B_CPU1_SB_DQ<18>")
	)
	(segment
		(start 77.775562 -220.594428)
		(end 77.548994 -220.36786)
		(width 0.18288)
		(layer "In2.Cu")
		(net "M_B_CPU1_SB_DQ<18>")
	)
	(segment
		(start 84.855812 -226.265994)
		(end 84.622894 -226.265994)
		(width 0.088646)
		(layer "In2.Cu")
		(net "M_B_CPU1_SB_DQ<18>")
	)
	(segment
		(start 61.831982 -212.064092)
		(end 61.572902 -212.323172)
		(width 0.18288)
		(layer "In2.Cu")
		(net "M_B_CPU1_SB_DQ<18>")
	)
	(segment
		(start 85.614764 -227.159058)
		(end 85.608668 -227.155502)
		(width 0.088646)
		(layer "In2.Cu")
		(net "M_B_CPU1_SB_DQ<18>")
	)
	(segment
		(start 79.54645 -222.09252)
		(end 79.722218 -221.917006)
		(width 0.18288)
		(layer "In2.Cu")
		(net "M_B_CPU1_SB_DQ<18>")
	)
	(segment
		(start 78.72349 -220.918278)
		(end 78.72349 -220.645482)
		(width 0.18288)
		(layer "In2.Cu")
		(net "M_B_CPU1_SB_DQ<18>")
	)
	(segment
		(start 78.496922 -220.418914)
		(end 78.224126 -220.418914)
		(width 0.18288)
		(layer "In2.Cu")
		(net "M_B_CPU1_SB_DQ<18>")
	)
	(segment
		(start 55.542434 -212.246972)
		(end 54.696614 -213.092792)
		(width 0.18288)
		(layer "In2.Cu")
		(net "M_B_CPU1_SB_DQ<18>")
	)
	(segment
		(start 84.136738 -225.941382)
		(end 83.122516 -225.941382)
		(width 0.18288)
		(layer "In2.Cu")
		(net "M_B_CPU1_SB_DQ<18>")
	)
	(segment
		(start 65.94221 -212.236304)
		(end 65.62979 -211.923884)
		(width 0.18288)
		(layer "In2.Cu")
		(net "M_B_CPU1_SB_DQ<18>")
	)
	(segment
		(start 80.221582 -222.41637)
		(end 80.045814 -222.591884)
		(width 0.18288)
		(layer "In2.Cu")
		(net "M_B_CPU1_SB_DQ<18>")
	)
	(segment
		(start 78.77429 -221.593156)
		(end 78.547722 -221.366588)
		(width 0.18288)
		(layer "In2.Cu")
		(net "M_B_CPU1_SB_DQ<18>")
	)
	(segment
		(start 75.727306 -217.649298)
		(end 75.500738 -217.42273)
		(width 0.18288)
		(layer "In2.Cu")
		(net "M_B_CPU1_SB_DQ<18>")
	)
	(segment
		(start 56.914542 -211.929472)
		(end 56.597042 -212.246972)
		(width 0.18288)
		(layer "In2.Cu")
		(net "M_B_CPU1_SB_DQ<18>")
	)
	(segment
		(start 77.498194 -219.420186)
		(end 77.225398 -219.420186)
		(width 0.18288)
		(layer "In2.Cu")
		(net "M_B_CPU1_SB_DQ<18>")
	)
	(segment
		(start 84.298282 -225.941382)
		(end 84.136738 -225.941382)
		(width 0.088646)
		(layer "In2.Cu")
		(net "M_B_CPU1_SB_DQ<18>")
	)
	(segment
		(start 78.224126 -220.418914)
		(end 78.048358 -220.594428)
		(width 0.18288)
		(layer "In2.Cu")
		(net "M_B_CPU1_SB_DQ<18>")
	)
	(segment
		(start 80.545178 -223.091248)
		(end 80.720946 -222.915734)
		(width 0.18288)
		(layer "In2.Cu")
		(net "M_B_CPU1_SB_DQ<18>")
	)
	(segment
		(start 56.597042 -212.246972)
		(end 55.542434 -212.246972)
		(width 0.18288)
		(layer "In2.Cu")
		(net "M_B_CPU1_SB_DQ<18>")
	)
	(segment
		(start 84.622894 -226.265994)
		(end 84.298282 -225.941382)
		(width 0.088646)
		(layer "In2.Cu")
		(net "M_B_CPU1_SB_DQ<18>")
	)
	(segment
		(start 82.04327 -224.58934)
		(end 81.770474 -224.58934)
		(width 0.18288)
		(layer "In2.Cu")
		(net "M_B_CPU1_SB_DQ<18>")
	)
	(segment
		(start 87.395812 -228.950012)
		(end 87.392764 -228.948488)
		(width 0.088646)
		(layer "In2.Cu")
		(net "M_B_CPU1_SB_DQ<18>")
	)
	(segment
		(start 75.052174 -217.598244)
		(end 74.779378 -217.598244)
		(width 0.18288)
		(layer "In2.Cu")
		(net "M_B_CPU1_SB_DQ<18>")
	)
	(segment
		(start 88.332564 -228.948488)
		(end 88.33231 -228.948488)
		(width 0.088646)
		(layer "In2.Cu")
		(net "M_B_CPU1_SB_DQ<18>")
	)
	(segment
		(start 81.493106 -223.415098)
		(end 81.22031 -223.415098)
		(width 0.18288)
		(layer "In2.Cu")
		(net "M_B_CPU1_SB_DQ<18>")
	)
	(segment
		(start 79.54645 -222.365316)
		(end 79.54645 -222.09252)
		(width 0.18288)
		(layer "In2.Cu")
		(net "M_B_CPU1_SB_DQ<18>")
	)
	(segment
		(start 79.047086 -221.593156)
		(end 78.77429 -221.593156)
		(width 0.18288)
		(layer "In2.Cu")
		(net "M_B_CPU1_SB_DQ<18>")
	)
	(segment
		(start 59.228482 -212.246972)
		(end 58.423048 -212.246972)
		(width 0.18288)
		(layer "In2.Cu")
		(net "M_B_CPU1_SB_DQ<18>")
	)
	(arc
		(start 85.138514 -226.341686)
		(mid 85.002145 -226.285244)
		(end 84.855812 -226.265994)
		(width 0.088646)
		(layer "In2.Cu")
		(net "M_B_CPU1_SB_DQ<18>")
	)
	(arc
		(start 87.392764 -228.948488)
		(mid 87.205566 -228.898311)
		(end 87.018368 -228.948488)
		(width 0.088646)
		(layer "In2.Cu")
		(net "M_B_CPU1_SB_DQ<18>")
	)
	(arc
		(start 89.666064 -229.169214)
		(mid 89.625679 -229.150809)
		(end 89.586562 -229.129844)
		(width 0.088646)
		(layer "In2.Cu")
		(net "M_B_CPU1_SB_DQ<18>")
	)
	(arc
		(start 85.891116 -227.64496)
		(mid 85.8172 -227.365458)
		(end 85.614764 -227.159058)
		(width 0.088646)
		(layer "In2.Cu")
		(net "M_B_CPU1_SB_DQ<18>")
	)
	(arc
		(start 86.361016 -228.440488)
		(mid 86.280854 -228.168299)
		(end 86.078568 -227.969318)
		(width 0.088646)
		(layer "In2.Cu")
		(net "M_B_CPU1_SB_DQ<18>")
	)
	(arc
		(start 89.96553 -229.272846)
		(mid 89.960196 -229.272892)
		(end 89.954862 -229.272846)
		(width 0.088646)
		(layer "In2.Cu")
		(net "M_B_CPU1_SB_DQ<18>")
	)
	(arc
		(start 88.897968 -228.948488)
		(mid 88.615266 -229.02423)
		(end 88.332564 -228.948488)
		(width 0.088646)
		(layer "In2.Cu")
		(net "M_B_CPU1_SB_DQ<18>")
	)
	(arc
		(start 86.548214 -228.783134)
		(mid 86.411169 -228.646174)
		(end 86.361016 -228.45903)
		(width 0.088646)
		(layer "In2.Cu")
		(net "M_B_CPU1_SB_DQ<18>")
	)
	(arc
		(start 87.018368 -228.948488)
		(mid 86.92642 -228.973125)
		(end 86.834472 -228.948488)
		(width 0.088646)
		(layer "In2.Cu")
		(net "M_B_CPU1_SB_DQ<18>")
	)
	(arc
		(start 89.954862 -229.272846)
		(mid 89.91069 -229.267257)
		(end 89.868248 -229.253796)
		(width 0.088646)
		(layer "In2.Cu")
		(net "M_B_CPU1_SB_DQ<18>")
	)
	(arc
		(start 89.272364 -228.948234)
		(mid 89.08767 -228.898133)
		(end 88.902286 -228.945694)
		(width 0.088646)
		(layer "In2.Cu")
		(net "M_B_CPU1_SB_DQ<18>")
	)
	(arc
		(start 86.069678 -227.964238)
		(mid 85.938764 -227.827878)
		(end 85.891116 -227.64496)
		(width 0.088646)
		(layer "In2.Cu")
		(net "M_B_CPU1_SB_DQ<18>")
	)
	(arc
		(start 85.599778 -227.150422)
		(mid 85.468864 -227.014062)
		(end 85.421216 -226.831144)
		(width 0.088646)
		(layer "In2.Cu")
		(net "M_B_CPU1_SB_DQ<18>")
	)
	(arc
		(start 87.958168 -228.948488)
		(mid 87.677201 -229.024135)
		(end 87.395812 -228.950012)
		(width 0.088646)
		(layer "In2.Cu")
		(net "M_B_CPU1_SB_DQ<18>")
	)
	(arc
		(start 88.33231 -228.948488)
		(mid 88.145256 -228.898438)
		(end 87.958168 -228.948488)
		(width 0.088646)
		(layer "In2.Cu")
		(net "M_B_CPU1_SB_DQ<18>")
	)
	(arc
		(start 85.421216 -226.831144)
		(mid 85.348981 -226.55462)
		(end 85.150706 -226.348798)
		(width 0.088646)
		(layer "In2.Cu")
		(net "M_B_CPU1_SB_DQ<18>")
	)
	(segment
		(start 46.964346 -211.766658)
		(end 45.859446 -211.766658)
		(width 0.20066)
		(layer "F.Cu")
		(net "M_B_CPU1_SB_DQ<17>")
	)
	(segment
		(start 40.682672 -211.332826)
		(end 40.520112 -211.495386)
		(width 0.20066)
		(layer "F.Cu")
		(net "M_B_CPU1_SB_DQ<17>")
	)
	(segment
		(start 41.29151 -211.332826)
		(end 40.682672 -211.332826)
		(width 0.20066)
		(layer "F.Cu")
		(net "M_B_CPU1_SB_DQ<17>")
	)
	(segment
		(start 43.285918 -211.341716)
		(end 41.3004 -211.341716)
		(width 0.1016)
		(layer "F.Cu")
		(net "M_B_CPU1_SB_DQ<17>")
	)
	(segment
		(start 45.859446 -211.766658)
		(end 44.22013 -211.766658)
		(width 0.20066)
		(layer "F.Cu")
		(net "M_B_CPU1_SB_DQ<17>")
	)
	(segment
		(start 40.520112 -211.823554)
		(end 40.36568 -211.977986)
		(width 0.20066)
		(layer "F.Cu")
		(net "M_B_CPU1_SB_DQ<17>")
	)
	(segment
		(start 39.861236 -211.977986)
		(end 39.649908 -211.766658)
		(width 0.20066)
		(layer "F.Cu")
		(net "M_B_CPU1_SB_DQ<17>")
	)
	(segment
		(start 44.22013 -211.766658)
		(end 43.795188 -211.341716)
		(width 0.20066)
		(layer "F.Cu")
		(net "M_B_CPU1_SB_DQ<17>")
	)
	(segment
		(start 41.3004 -211.341716)
		(end 41.29151 -211.332826)
		(width 0.1016)
		(layer "F.Cu")
		(net "M_B_CPU1_SB_DQ<17>")
	)
	(segment
		(start 88.615266 -228.99497)
		(end 88.615266 -228.459284)
		(width 0.20066)
		(layer "F.Cu")
		(net "M_B_CPU1_SB_DQ<17>")
	)
	(segment
		(start 88.615266 -228.459284)
		(end 88.615012 -228.45903)
		(width 0.20066)
		(layer "F.Cu")
		(net "M_B_CPU1_SB_DQ<17>")
	)
	(segment
		(start 39.649908 -211.766658)
		(end 38.315646 -211.766658)
		(width 0.20066)
		(layer "F.Cu")
		(net "M_B_CPU1_SB_DQ<17>")
	)
	(segment
		(start 43.795188 -211.341716)
		(end 43.616626 -211.341716)
		(width 0.20066)
		(layer "F.Cu")
		(net "M_B_CPU1_SB_DQ<17>")
	)
	(segment
		(start 43.616626 -211.341716)
		(end 43.285918 -211.341716)
		(width 0.101854)
		(layer "F.Cu")
		(net "M_B_CPU1_SB_DQ<17>")
	)
	(segment
		(start 40.36568 -211.977986)
		(end 39.861236 -211.977986)
		(width 0.20066)
		(layer "F.Cu")
		(net "M_B_CPU1_SB_DQ<17>")
	)
	(segment
		(start 40.520112 -211.495386)
		(end 40.520112 -211.823554)
		(width 0.20066)
		(layer "F.Cu")
		(net "M_B_CPU1_SB_DQ<17>")
	)
	(segment
		(start 49.072038 -211.344002)
		(end 48.878998 -211.150962)
		(width 0.18288)
		(layer "In2.Cu")
		(net "M_B_CPU1_SB_DQ<17>")
	)
	(segment
		(start 86.640162 -227.659184)
		(end 86.640162 -227.636324)
		(width 0.088646)
		(layer "In2.Cu")
		(net "M_B_CPU1_SB_DQ<17>")
	)
	(segment
		(start 51.504342 -211.938362)
		(end 51.25085 -212.191854)
		(width 0.18288)
		(layer "In2.Cu")
		(net "M_B_CPU1_SB_DQ<17>")
	)
	(segment
		(start 50.369978 -212.000592)
		(end 50.369978 -211.537042)
		(width 0.18288)
		(layer "In2.Cu")
		(net "M_B_CPU1_SB_DQ<17>")
	)
	(segment
		(start 55.668926 -211.327492)
		(end 54.815486 -212.180932)
		(width 0.18288)
		(layer "In2.Cu")
		(net "M_B_CPU1_SB_DQ<17>")
	)
	(segment
		(start 85.983064 -226.506786)
		(end 85.970872 -226.499674)
		(width 0.088646)
		(layer "In2.Cu")
		(net "M_B_CPU1_SB_DQ<17>")
	)
	(segment
		(start 63.245746 -211.543392)
		(end 62.038992 -211.543392)
		(width 0.18288)
		(layer "In2.Cu")
		(net "M_B_CPU1_SB_DQ<17>")
	)
	(segment
		(start 50.176938 -211.344002)
		(end 49.072038 -211.344002)
		(width 0.18288)
		(layer "In2.Cu")
		(net "M_B_CPU1_SB_DQ<17>")
	)
	(segment
		(start 87.890604 -228.767132)
		(end 87.862664 -228.783388)
		(width 0.088646)
		(layer "In2.Cu")
		(net "M_B_CPU1_SB_DQ<17>")
	)
	(segment
		(start 61.639958 -211.144358)
		(end 60.31357 -211.144358)
		(width 0.18288)
		(layer "In2.Cu")
		(net "M_B_CPU1_SB_DQ<17>")
	)
	(segment
		(start 48.025558 -211.885276)
		(end 47.832264 -212.07857)
		(width 0.18288)
		(layer "In2.Cu")
		(net "M_B_CPU1_SB_DQ<17>")
	)
	(segment
		(start 48.218598 -210.495388)
		(end 48.025558 -210.688428)
		(width 0.18288)
		(layer "In2.Cu")
		(net "M_B_CPU1_SB_DQ<17>")
	)
	(segment
		(start 85.138514 -225.69297)
		(end 85.123782 -225.701606)
		(width 0.088646)
		(layer "In2.Cu")
		(net "M_B_CPU1_SB_DQ<17>")
	)
	(segment
		(start 62.038992 -211.543392)
		(end 61.639958 -211.144358)
		(width 0.18288)
		(layer "In2.Cu")
		(net "M_B_CPU1_SB_DQ<17>")
	)
	(segment
		(start 69.491352 -211.589366)
		(end 68.270628 -211.589366)
		(width 0.18288)
		(layer "In2.Cu")
		(net "M_B_CPU1_SB_DQ<17>")
	)
	(segment
		(start 67.371468 -210.891628)
		(end 67.371468 -211.396326)
		(width 0.18288)
		(layer "In2.Cu")
		(net "M_B_CPU1_SB_DQ<17>")
	)
	(segment
		(start 87.488268 -228.783388)
		(end 87.202264 -228.618034)
		(width 0.088646)
		(layer "In2.Cu")
		(net "M_B_CPU1_SB_DQ<17>")
	)
	(segment
		(start 83.609688 -225.142806)
		(end 83.416394 -224.949512)
		(width 0.18288)
		(layer "In2.Cu")
		(net "M_B_CPU1_SB_DQ<17>")
	)
	(segment
		(start 47.832264 -212.07857)
		(end 47.276258 -212.07857)
		(width 0.18288)
		(layer "In2.Cu")
		(net "M_B_CPU1_SB_DQ<17>")
	)
	(segment
		(start 86.170262 -226.831144)
		(end 86.170262 -226.822508)
		(width 0.088646)
		(layer "In2.Cu")
		(net "M_B_CPU1_SB_DQ<17>")
	)
	(segment
		(start 66.477642 -211.333334)
		(end 63.455804 -211.333334)
		(width 0.18288)
		(layer "In2.Cu")
		(net "M_B_CPU1_SB_DQ<17>")
	)
	(segment
		(start 50.56124 -212.191854)
		(end 50.369978 -212.000592)
		(width 0.18288)
		(layer "In2.Cu")
		(net "M_B_CPU1_SB_DQ<17>")
	)
	(segment
		(start 52.153566 -211.938362)
		(end 51.504342 -211.938362)
		(width 0.18288)
		(layer "In2.Cu")
		(net "M_B_CPU1_SB_DQ<17>")
	)
	(segment
		(start 67.564508 -210.698588)
		(end 67.371468 -210.891628)
		(width 0.18288)
		(layer "In2.Cu")
		(net "M_B_CPU1_SB_DQ<17>")
	)
	(segment
		(start 52.396136 -212.180932)
		(end 52.153566 -211.938362)
		(width 0.18288)
		(layer "In2.Cu")
		(net "M_B_CPU1_SB_DQ<17>")
	)
	(segment
		(start 54.815486 -212.180932)
		(end 52.396136 -212.180932)
		(width 0.18288)
		(layer "In2.Cu")
		(net "M_B_CPU1_SB_DQ<17>")
	)
	(segment
		(start 63.455804 -211.333334)
		(end 63.245746 -211.543392)
		(width 0.18288)
		(layer "In2.Cu")
		(net "M_B_CPU1_SB_DQ<17>")
	)
	(segment
		(start 83.416394 -224.949512)
		(end 83.416394 -224.583244)
		(width 0.18288)
		(layer "In2.Cu")
		(net "M_B_CPU1_SB_DQ<17>")
	)
	(segment
		(start 68.077588 -211.396326)
		(end 68.077588 -210.891628)
		(width 0.18288)
		(layer "In2.Cu")
		(net "M_B_CPU1_SB_DQ<17>")
	)
	(segment
		(start 68.270628 -211.589366)
		(end 68.077588 -211.396326)
		(width 0.18288)
		(layer "In2.Cu")
		(net "M_B_CPU1_SB_DQ<17>")
	)
	(segment
		(start 47.276258 -212.07857)
		(end 46.964346 -211.766658)
		(width 0.18288)
		(layer "In2.Cu")
		(net "M_B_CPU1_SB_DQ<17>")
	)
	(segment
		(start 84.385912 -225.54946)
		(end 84.38134 -225.54946)
		(width 0.088646)
		(layer "In2.Cu")
		(net "M_B_CPU1_SB_DQ<17>")
	)
	(segment
		(start 67.884548 -210.698588)
		(end 67.564508 -210.698588)
		(width 0.18288)
		(layer "In2.Cu")
		(net "M_B_CPU1_SB_DQ<17>")
	)
	(segment
		(start 86.922864 -228.134926)
		(end 86.922864 -228.134672)
		(width 0.088646)
		(layer "In2.Cu")
		(net "M_B_CPU1_SB_DQ<17>")
	)
	(segment
		(start 67.178428 -211.589366)
		(end 66.733674 -211.589366)
		(width 0.18288)
		(layer "In2.Cu")
		(net "M_B_CPU1_SB_DQ<17>")
	)
	(segment
		(start 85.5218 -225.69805)
		(end 85.51291 -225.69297)
		(width 0.088646)
		(layer "In2.Cu")
		(net "M_B_CPU1_SB_DQ<17>")
	)
	(segment
		(start 74.571352 -216.669366)
		(end 69.491352 -211.589366)
		(width 0.18288)
		(layer "In2.Cu")
		(net "M_B_CPU1_SB_DQ<17>")
	)
	(segment
		(start 88.615012 -228.45903)
		(end 87.890604 -228.767132)
		(width 0.088646)
		(layer "In2.Cu")
		(net "M_B_CPU1_SB_DQ<17>")
	)
	(segment
		(start 68.077588 -210.891628)
		(end 67.884548 -210.698588)
		(width 0.18288)
		(layer "In2.Cu")
		(net "M_B_CPU1_SB_DQ<17>")
	)
	(segment
		(start 75.51801 -216.669366)
		(end 74.571352 -216.669366)
		(width 0.18288)
		(layer "In2.Cu")
		(net "M_B_CPU1_SB_DQ<17>")
	)
	(segment
		(start 59.447938 -211.504276)
		(end 59.271154 -211.327492)
		(width 0.18288)
		(layer "In2.Cu")
		(net "M_B_CPU1_SB_DQ<17>")
	)
	(segment
		(start 48.878998 -211.150962)
		(end 48.878998 -210.688428)
		(width 0.18288)
		(layer "In2.Cu")
		(net "M_B_CPU1_SB_DQ<17>")
	)
	(segment
		(start 59.271154 -211.327492)
		(end 55.668926 -211.327492)
		(width 0.18288)
		(layer "In2.Cu")
		(net "M_B_CPU1_SB_DQ<17>")
	)
	(segment
		(start 66.733674 -211.589366)
		(end 66.477642 -211.333334)
		(width 0.18288)
		(layer "In2.Cu")
		(net "M_B_CPU1_SB_DQ<17>")
	)
	(segment
		(start 60.31357 -211.144358)
		(end 59.953652 -211.504276)
		(width 0.18288)
		(layer "In2.Cu")
		(net "M_B_CPU1_SB_DQ<17>")
	)
	(segment
		(start 51.25085 -212.191854)
		(end 50.56124 -212.191854)
		(width 0.18288)
		(layer "In2.Cu")
		(net "M_B_CPU1_SB_DQ<17>")
	)
	(segment
		(start 50.369978 -211.537042)
		(end 50.176938 -211.344002)
		(width 0.18288)
		(layer "In2.Cu")
		(net "M_B_CPU1_SB_DQ<17>")
	)
	(segment
		(start 83.416394 -224.583244)
		(end 75.51801 -216.669366)
		(width 0.18288)
		(layer "In2.Cu")
		(net "M_B_CPU1_SB_DQ<17>")
	)
	(segment
		(start 48.878998 -210.688428)
		(end 48.685958 -210.495388)
		(width 0.18288)
		(layer "In2.Cu")
		(net "M_B_CPU1_SB_DQ<17>")
	)
	(segment
		(start 67.371468 -211.396326)
		(end 67.178428 -211.589366)
		(width 0.18288)
		(layer "In2.Cu")
		(net "M_B_CPU1_SB_DQ<17>")
	)
	(segment
		(start 59.953652 -211.504276)
		(end 59.447938 -211.504276)
		(width 0.18288)
		(layer "In2.Cu")
		(net "M_B_CPU1_SB_DQ<17>")
	)
	(segment
		(start 48.685958 -210.495388)
		(end 48.218598 -210.495388)
		(width 0.18288)
		(layer "In2.Cu")
		(net "M_B_CPU1_SB_DQ<17>")
	)
	(segment
		(start 84.38134 -225.54946)
		(end 84.092034 -225.260154)
		(width 0.088646)
		(layer "In2.Cu")
		(net "M_B_CPU1_SB_DQ<17>")
	)
	(segment
		(start 84.092034 -225.260154)
		(end 83.974686 -225.142806)
		(width 0.18288)
		(layer "In2.Cu")
		(net "M_B_CPU1_SB_DQ<17>")
	)
	(segment
		(start 83.974686 -225.142806)
		(end 83.609688 -225.142806)
		(width 0.18288)
		(layer "In2.Cu")
		(net "M_B_CPU1_SB_DQ<17>")
	)
	(segment
		(start 86.452964 -227.320602)
		(end 86.446868 -227.317046)
		(width 0.088646)
		(layer "In2.Cu")
		(net "M_B_CPU1_SB_DQ<17>")
	)
	(segment
		(start 48.025558 -210.688428)
		(end 48.025558 -211.885276)
		(width 0.18288)
		(layer "In2.Cu")
		(net "M_B_CPU1_SB_DQ<17>")
	)
	(arc
		(start 86.446868 -227.317046)
		(mid 86.244281 -227.110695)
		(end 86.170262 -226.831144)
		(width 0.088646)
		(layer "In2.Cu")
		(net "M_B_CPU1_SB_DQ<17>")
	)
	(arc
		(start 87.110316 -228.45903)
		(mid 87.060076 -228.271829)
		(end 86.922864 -228.134926)
		(width 0.088646)
		(layer "In2.Cu")
		(net "M_B_CPU1_SB_DQ<17>")
	)
	(arc
		(start 86.170262 -226.822508)
		(mid 86.117992 -226.640143)
		(end 85.983064 -226.506786)
		(width 0.088646)
		(layer "In2.Cu")
		(net "M_B_CPU1_SB_DQ<17>")
	)
	(arc
		(start 85.970872 -226.499674)
		(mid 85.772644 -226.293826)
		(end 85.700362 -226.017328)
		(width 0.088646)
		(layer "In2.Cu")
		(net "M_B_CPU1_SB_DQ<17>")
	)
	(arc
		(start 87.202264 -228.618034)
		(mid 87.134934 -228.550876)
		(end 87.110316 -228.45903)
		(width 0.088646)
		(layer "In2.Cu")
		(net "M_B_CPU1_SB_DQ<17>")
	)
	(arc
		(start 86.640162 -227.636324)
		(mid 86.587892 -227.453959)
		(end 86.452964 -227.320602)
		(width 0.088646)
		(layer "In2.Cu")
		(net "M_B_CPU1_SB_DQ<17>")
	)
	(arc
		(start 84.57311 -225.69297)
		(mid 84.474798 -225.627363)
		(end 84.385912 -225.54946)
		(width 0.088646)
		(layer "In2.Cu")
		(net "M_B_CPU1_SB_DQ<17>")
	)
	(arc
		(start 87.862664 -228.783388)
		(mid 87.675466 -228.833565)
		(end 87.488268 -228.783388)
		(width 0.088646)
		(layer "In2.Cu")
		(net "M_B_CPU1_SB_DQ<17>")
	)
	(arc
		(start 86.922864 -228.134672)
		(mid 86.719383 -227.933868)
		(end 86.640162 -227.659184)
		(width 0.088646)
		(layer "In2.Cu")
		(net "M_B_CPU1_SB_DQ<17>")
	)
	(arc
		(start 85.700362 -226.017328)
		(mid 85.652683 -225.834428)
		(end 85.5218 -225.69805)
		(width 0.088646)
		(layer "In2.Cu")
		(net "M_B_CPU1_SB_DQ<17>")
	)
	(arc
		(start 85.51291 -225.69297)
		(mid 85.325712 -225.642827)
		(end 85.138514 -225.69297)
		(width 0.088646)
		(layer "In2.Cu")
		(net "M_B_CPU1_SB_DQ<17>")
	)
	(arc
		(start 85.123782 -225.701606)
		(mid 84.847341 -225.768772)
		(end 84.57311 -225.69297)
		(width 0.088646)
		(layer "In2.Cu")
		(net "M_B_CPU1_SB_DQ<17>")
	)
	(segment
		(start 44.490386 -213.46668)
		(end 44.065444 -213.041738)
		(width 0.20066)
		(layer "F.Cu")
		(net "M_B_CPU1_SB_DQ<16>")
	)
	(segment
		(start 41.547542 -213.041738)
		(end 41.299638 -213.041738)
		(width 0.101854)
		(layer "F.Cu")
		(net "M_B_CPU1_SB_DQ<16>")
	)
	(segment
		(start 41.29151 -213.03361)
		(end 40.729662 -213.03361)
		(width 0.20066)
		(layer "F.Cu")
		(net "M_B_CPU1_SB_DQ<16>")
	)
	(segment
		(start 44.065444 -213.041738)
		(end 43.616626 -213.041738)
		(width 0.20066)
		(layer "F.Cu")
		(net "M_B_CPU1_SB_DQ<16>")
	)
	(segment
		(start 40.729662 -213.03361)
		(end 40.520112 -213.24316)
		(width 0.20066)
		(layer "F.Cu")
		(net "M_B_CPU1_SB_DQ<16>")
	)
	(segment
		(start 40.520112 -213.53272)
		(end 40.347392 -213.70544)
		(width 0.20066)
		(layer "F.Cu")
		(net "M_B_CPU1_SB_DQ<16>")
	)
	(segment
		(start 89.085166 -229.808532)
		(end 89.085166 -229.272846)
		(width 0.20066)
		(layer "F.Cu")
		(net "M_B_CPU1_SB_DQ<16>")
	)
	(segment
		(start 39.888668 -213.70544)
		(end 39.649908 -213.46668)
		(width 0.20066)
		(layer "F.Cu")
		(net "M_B_CPU1_SB_DQ<16>")
	)
	(segment
		(start 45.859446 -213.46668)
		(end 44.490386 -213.46668)
		(width 0.20066)
		(layer "F.Cu")
		(net "M_B_CPU1_SB_DQ<16>")
	)
	(segment
		(start 43.616626 -213.041738)
		(end 41.547542 -213.041738)
		(width 0.1016)
		(layer "F.Cu")
		(net "M_B_CPU1_SB_DQ<16>")
	)
	(segment
		(start 41.299638 -213.041738)
		(end 41.29151 -213.03361)
		(width 0.101854)
		(layer "F.Cu")
		(net "M_B_CPU1_SB_DQ<16>")
	)
	(segment
		(start 40.520112 -213.24316)
		(end 40.520112 -213.53272)
		(width 0.20066)
		(layer "F.Cu")
		(net "M_B_CPU1_SB_DQ<16>")
	)
	(segment
		(start 40.347392 -213.70544)
		(end 39.888668 -213.70544)
		(width 0.20066)
		(layer "F.Cu")
		(net "M_B_CPU1_SB_DQ<16>")
	)
	(segment
		(start 89.084912 -229.808786)
		(end 89.085166 -229.808532)
		(width 0.20066)
		(layer "F.Cu")
		(net "M_B_CPU1_SB_DQ<16>")
	)
	(segment
		(start 39.649908 -213.46668)
		(end 38.315646 -213.46668)
		(width 0.20066)
		(layer "F.Cu")
		(net "M_B_CPU1_SB_DQ<16>")
	)
	(segment
		(start 46.964346 -213.46668)
		(end 45.859446 -213.46668)
		(width 0.20066)
		(layer "F.Cu")
		(net "M_B_CPU1_SB_DQ<16>")
	)
	(segment
		(start 87.016336 -229.592632)
		(end 86.975188 -229.568502)
		(width 0.088646)
		(layer "In2.Cu")
		(net "M_B_CPU1_SB_DQ<16>")
	)
	(segment
		(start 62.616588 -213.53145)
		(end 62.240668 -213.53145)
		(width 0.18288)
		(layer "In2.Cu")
		(net "M_B_CPU1_SB_DQ<16>")
	)
	(segment
		(start 69.090286 -212.644482)
		(end 66.771774 -212.644482)
		(width 0.18288)
		(layer "In2.Cu")
		(net "M_B_CPU1_SB_DQ<16>")
	)
	(segment
		(start 49.362106 -213.020656)
		(end 48.383698 -213.020656)
		(width 0.18288)
		(layer "In2.Cu")
		(net "M_B_CPU1_SB_DQ<16>")
	)
	(segment
		(start 50.405792 -213.202266)
		(end 50.405792 -213.770464)
		(width 0.18288)
		(layer "In2.Cu")
		(net "M_B_CPU1_SB_DQ<16>")
	)
	(segment
		(start 58.058558 -213.04377)
		(end 57.865518 -213.23681)
		(width 0.18288)
		(layer "In2.Cu")
		(net "M_B_CPU1_SB_DQ<16>")
	)
	(segment
		(start 47.454058 -213.65337)
		(end 47.267368 -213.46668)
		(width 0.18288)
		(layer "In2.Cu")
		(net "M_B_CPU1_SB_DQ<16>")
	)
	(segment
		(start 87.393018 -229.597204)
		(end 87.392764 -229.597204)
		(width 0.088646)
		(layer "In2.Cu")
		(net "M_B_CPU1_SB_DQ<16>")
	)
	(segment
		(start 52.073556 -213.870794)
		(end 51.2445 -213.041738)
		(width 0.18288)
		(layer "In2.Cu")
		(net "M_B_CPU1_SB_DQ<16>")
	)
	(segment
		(start 57.865518 -213.23681)
		(end 57.865518 -213.479634)
		(width 0.18288)
		(layer "In2.Cu")
		(net "M_B_CPU1_SB_DQ<16>")
	)
	(segment
		(start 51.2445 -213.041738)
		(end 50.56632 -213.041738)
		(width 0.18288)
		(layer "In2.Cu")
		(net "M_B_CPU1_SB_DQ<16>")
	)
	(segment
		(start 86.170516 -228.459284)
		(end 86.170516 -228.45903)
		(width 0.088646)
		(layer "In2.Cu")
		(net "M_B_CPU1_SB_DQ<16>")
	)
	(segment
		(start 87.020654 -229.595172)
		(end 87.01913 -229.59441)
		(width 0.088646)
		(layer "In2.Cu")
		(net "M_B_CPU1_SB_DQ<16>")
	)
	(segment
		(start 56.471566 -212.860382)
		(end 55.655972 -212.860382)
		(width 0.18288)
		(layer "In2.Cu")
		(net "M_B_CPU1_SB_DQ<16>")
	)
	(segment
		(start 58.652918 -212.76183)
		(end 58.370978 -213.04377)
		(width 0.18288)
		(layer "In2.Cu")
		(net "M_B_CPU1_SB_DQ<16>")
	)
	(segment
		(start 50.245772 -213.930484)
		(end 49.714404 -213.930484)
		(width 0.18288)
		(layer "In2.Cu")
		(net "M_B_CPU1_SB_DQ<16>")
	)
	(segment
		(start 89.085166 -229.272846)
		(end 89.084912 -229.272846)
		(width 0.088646)
		(layer "In2.Cu")
		(net "M_B_CPU1_SB_DQ<16>")
	)
	(segment
		(start 49.554384 -213.770464)
		(end 49.554384 -213.212934)
		(width 0.18288)
		(layer "In2.Cu")
		(net "M_B_CPU1_SB_DQ<16>")
	)
	(segment
		(start 57.865518 -213.479634)
		(end 57.672478 -213.672674)
		(width 0.18288)
		(layer "In2.Cu")
		(net "M_B_CPU1_SB_DQ<16>")
	)
	(segment
		(start 66.771774 -212.644482)
		(end 66.392298 -213.023958)
		(width 0.18288)
		(layer "In2.Cu")
		(net "M_B_CPU1_SB_DQ<16>")
	)
	(segment
		(start 59.953144 -213.181184)
		(end 59.678316 -213.181184)
		(width 0.18288)
		(layer "In2.Cu")
		(net "M_B_CPU1_SB_DQ<16>")
	)
	(segment
		(start 47.997618 -214.22487)
		(end 47.647098 -214.22487)
		(width 0.18288)
		(layer "In2.Cu")
		(net "M_B_CPU1_SB_DQ<16>")
	)
	(segment
		(start 60.092336 -213.041992)
		(end 59.953144 -213.181184)
		(width 0.18288)
		(layer "In2.Cu")
		(net "M_B_CPU1_SB_DQ<16>")
	)
	(segment
		(start 49.714404 -213.930484)
		(end 49.554384 -213.770464)
		(width 0.18288)
		(layer "In2.Cu")
		(net "M_B_CPU1_SB_DQ<16>")
	)
	(segment
		(start 85.991954 -228.139752)
		(end 85.983064 -228.134672)
		(width 0.088646)
		(layer "In2.Cu")
		(net "M_B_CPU1_SB_DQ<16>")
	)
	(segment
		(start 59.258962 -212.76183)
		(end 58.652918 -212.76183)
		(width 0.18288)
		(layer "In2.Cu")
		(net "M_B_CPU1_SB_DQ<16>")
	)
	(segment
		(start 61.75121 -213.041992)
		(end 60.092336 -213.041992)
		(width 0.18288)
		(layer "In2.Cu")
		(net "M_B_CPU1_SB_DQ<16>")
	)
	(segment
		(start 49.554384 -213.212934)
		(end 49.362106 -213.020656)
		(width 0.18288)
		(layer "In2.Cu")
		(net "M_B_CPU1_SB_DQ<16>")
	)
	(segment
		(start 48.190658 -214.03183)
		(end 47.997618 -214.22487)
		(width 0.18288)
		(layer "In2.Cu")
		(net "M_B_CPU1_SB_DQ<16>")
	)
	(segment
		(start 59.678316 -213.181184)
		(end 59.258962 -212.76183)
		(width 0.18288)
		(layer "In2.Cu")
		(net "M_B_CPU1_SB_DQ<16>")
	)
	(segment
		(start 85.50275 -227.31476)
		(end 85.503004 -227.314252)
		(width 0.088646)
		(layer "In2.Cu")
		(net "M_B_CPU1_SB_DQ<16>")
	)
	(segment
		(start 54.64556 -213.870794)
		(end 52.073556 -213.870794)
		(width 0.18288)
		(layer "In2.Cu")
		(net "M_B_CPU1_SB_DQ<16>")
	)
	(segment
		(start 57.098438 -213.672674)
		(end 56.905398 -213.479634)
		(width 0.18288)
		(layer "In2.Cu")
		(net "M_B_CPU1_SB_DQ<16>")
	)
	(segment
		(start 86.738968 -229.113842)
		(end 86.452964 -228.948488)
		(width 0.088646)
		(layer "In2.Cu")
		(net "M_B_CPU1_SB_DQ<16>")
	)
	(segment
		(start 47.267368 -213.46668)
		(end 46.964346 -213.46668)
		(width 0.18288)
		(layer "In2.Cu")
		(net "M_B_CPU1_SB_DQ<16>")
	)
	(segment
		(start 85.700362 -227.65258)
		(end 85.700362 -227.64496)
		(width 0.088646)
		(layer "In2.Cu")
		(net "M_B_CPU1_SB_DQ<16>")
	)
	(segment
		(start 84.855812 -226.456494)
		(end 84.138516 -226.456494)
		(width 0.088646)
		(layer "In2.Cu")
		(net "M_B_CPU1_SB_DQ<16>")
	)
	(segment
		(start 88.72982 -229.368096)
		(end 88.332564 -229.597204)
		(width 0.088646)
		(layer "In2.Cu")
		(net "M_B_CPU1_SB_DQ<16>")
	)
	(segment
		(start 87.01913 -229.59441)
		(end 87.016336 -229.592632)
		(width 0.088646)
		(layer "In2.Cu")
		(net "M_B_CPU1_SB_DQ<16>")
	)
	(segment
		(start 82.904076 -226.458272)
		(end 69.090286 -212.644482)
		(width 0.18288)
		(layer "In2.Cu")
		(net "M_B_CPU1_SB_DQ<16>")
	)
	(segment
		(start 47.454058 -214.03183)
		(end 47.454058 -213.65337)
		(width 0.18288)
		(layer "In2.Cu")
		(net "M_B_CPU1_SB_DQ<16>")
	)
	(segment
		(start 50.56632 -213.041738)
		(end 50.405792 -213.202266)
		(width 0.18288)
		(layer "In2.Cu")
		(net "M_B_CPU1_SB_DQ<16>")
	)
	(segment
		(start 56.905398 -213.479634)
		(end 56.905398 -213.294214)
		(width 0.18288)
		(layer "In2.Cu")
		(net "M_B_CPU1_SB_DQ<16>")
	)
	(segment
		(start 48.383698 -213.020656)
		(end 48.190658 -213.213696)
		(width 0.18288)
		(layer "In2.Cu")
		(net "M_B_CPU1_SB_DQ<16>")
	)
	(segment
		(start 55.655972 -212.860382)
		(end 54.64556 -213.870794)
		(width 0.18288)
		(layer "In2.Cu")
		(net "M_B_CPU1_SB_DQ<16>")
	)
	(segment
		(start 62.240668 -213.53145)
		(end 61.75121 -213.041992)
		(width 0.18288)
		(layer "In2.Cu")
		(net "M_B_CPU1_SB_DQ<16>")
	)
	(segment
		(start 48.190658 -213.213696)
		(end 48.190658 -214.03183)
		(width 0.18288)
		(layer "In2.Cu")
		(net "M_B_CPU1_SB_DQ<16>")
	)
	(segment
		(start 58.370978 -213.04377)
		(end 58.058558 -213.04377)
		(width 0.18288)
		(layer "In2.Cu")
		(net "M_B_CPU1_SB_DQ<16>")
	)
	(segment
		(start 84.136738 -226.458272)
		(end 82.904076 -226.458272)
		(width 0.18288)
		(layer "In2.Cu")
		(net "M_B_CPU1_SB_DQ<16>")
	)
	(segment
		(start 57.672478 -213.672674)
		(end 57.098438 -213.672674)
		(width 0.18288)
		(layer "In2.Cu")
		(net "M_B_CPU1_SB_DQ<16>")
	)
	(segment
		(start 63.12408 -213.023958)
		(end 62.616588 -213.53145)
		(width 0.18288)
		(layer "In2.Cu")
		(net "M_B_CPU1_SB_DQ<16>")
	)
	(segment
		(start 50.405792 -213.770464)
		(end 50.245772 -213.930484)
		(width 0.18288)
		(layer "In2.Cu")
		(net "M_B_CPU1_SB_DQ<16>")
	)
	(segment
		(start 66.392298 -213.023958)
		(end 63.12408 -213.023958)
		(width 0.18288)
		(layer "In2.Cu")
		(net "M_B_CPU1_SB_DQ<16>")
	)
	(segment
		(start 85.23097 -226.831144)
		(end 85.230462 -226.831144)
		(width 0.088646)
		(layer "In2.Cu")
		(net "M_B_CPU1_SB_DQ<16>")
	)
	(segment
		(start 47.647098 -214.22487)
		(end 47.454058 -214.03183)
		(width 0.18288)
		(layer "In2.Cu")
		(net "M_B_CPU1_SB_DQ<16>")
	)
	(segment
		(start 85.5218 -227.325682)
		(end 85.506814 -227.317046)
		(width 0.088646)
		(layer "In2.Cu")
		(net "M_B_CPU1_SB_DQ<16>")
	)
	(segment
		(start 84.138516 -226.456494)
		(end 84.136738 -226.458272)
		(width 0.088646)
		(layer "In2.Cu")
		(net "M_B_CPU1_SB_DQ<16>")
	)
	(segment
		(start 56.905398 -213.294214)
		(end 56.471566 -212.860382)
		(width 0.18288)
		(layer "In2.Cu")
		(net "M_B_CPU1_SB_DQ<16>")
	)
	(arc
		(start 85.506814 -227.317046)
		(mid 85.50478 -227.315907)
		(end 85.50275 -227.31476)
		(width 0.088646)
		(layer "In2.Cu")
		(net "M_B_CPU1_SB_DQ<16>")
	)
	(arc
		(start 85.983064 -228.134672)
		(mid 85.777992 -227.930993)
		(end 85.700362 -227.65258)
		(width 0.088646)
		(layer "In2.Cu")
		(net "M_B_CPU1_SB_DQ<16>")
	)
	(arc
		(start 88.332564 -229.597204)
		(mid 88.145256 -229.647347)
		(end 87.957914 -229.597204)
		(width 0.088646)
		(layer "In2.Cu")
		(net "M_B_CPU1_SB_DQ<16>")
	)
	(arc
		(start 86.830916 -229.272846)
		(mid 86.806268 -229.181017)
		(end 86.738968 -229.113842)
		(width 0.088646)
		(layer "In2.Cu")
		(net "M_B_CPU1_SB_DQ<16>")
	)
	(arc
		(start 86.170516 -228.45903)
		(mid 86.122837 -228.27613)
		(end 85.991954 -228.139752)
		(width 0.088646)
		(layer "In2.Cu")
		(net "M_B_CPU1_SB_DQ<16>")
	)
	(arc
		(start 89.084912 -229.272846)
		(mid 88.901094 -229.297097)
		(end 88.72982 -229.368096)
		(width 0.088646)
		(layer "In2.Cu")
		(net "M_B_CPU1_SB_DQ<16>")
	)
	(arc
		(start 87.957914 -229.597204)
		(mid 87.675466 -229.521521)
		(end 87.393018 -229.597204)
		(width 0.088646)
		(layer "In2.Cu")
		(net "M_B_CPU1_SB_DQ<16>")
	)
	(arc
		(start 86.975188 -229.568502)
		(mid 86.86888 -229.437353)
		(end 86.830916 -229.272846)
		(width 0.088646)
		(layer "In2.Cu")
		(net "M_B_CPU1_SB_DQ<16>")
	)
	(arc
		(start 85.230462 -226.831144)
		(mid 85.12073 -226.566226)
		(end 84.855812 -226.456494)
		(width 0.088646)
		(layer "In2.Cu")
		(net "M_B_CPU1_SB_DQ<16>")
	)
	(arc
		(start 86.452964 -228.948488)
		(mid 86.246204 -228.741725)
		(end 86.170516 -228.459284)
		(width 0.088646)
		(layer "In2.Cu")
		(net "M_B_CPU1_SB_DQ<16>")
	)
	(arc
		(start 85.700362 -227.64496)
		(mid 85.652683 -227.46206)
		(end 85.5218 -227.325682)
		(width 0.088646)
		(layer "In2.Cu")
		(net "M_B_CPU1_SB_DQ<16>")
	)
	(arc
		(start 85.503004 -227.314252)
		(mid 85.30362 -227.108372)
		(end 85.23097 -226.831144)
		(width 0.088646)
		(layer "In2.Cu")
		(net "M_B_CPU1_SB_DQ<16>")
	)
	(arc
		(start 87.392764 -229.597204)
		(mid 87.206422 -229.646592)
		(end 87.020654 -229.595172)
		(width 0.088646)
		(layer "In2.Cu")
		(net "M_B_CPU1_SB_DQ<16>")
	)
	(segment
		(start 49.959514 -214.316564)
		(end 49.143412 -214.316564)
		(width 0.20066)
		(layer "F.Cu")
		(net "M_B_CPU1_SB_DQ<15>")
	)
	(segment
		(start 44.749466 -214.741506)
		(end 44.735242 -214.75573)
		(width 0.101854)
		(layer "F.Cu")
		(net "M_B_CPU1_SB_DQ<15>")
	)
	(segment
		(start 49.143412 -214.316564)
		(end 48.935894 -214.524082)
		(width 0.20066)
		(layer "F.Cu")
		(net "M_B_CPU1_SB_DQ<15>")
	)
	(segment
		(start 47.753778 -214.44077)
		(end 47.753778 -214.592408)
		(width 0.20066)
		(layer "F.Cu")
		(net "M_B_CPU1_SB_DQ<15>")
	)
	(segment
		(start 90.024712 -231.436418)
		(end 90.024966 -231.436164)
		(width 0.20066)
		(layer "F.Cu")
		(net "M_B_CPU1_SB_DQ<15>")
	)
	(segment
		(start 48.277526 -214.312246)
		(end 47.882302 -214.312246)
		(width 0.20066)
		(layer "F.Cu")
		(net "M_B_CPU1_SB_DQ<15>")
	)
	(segment
		(start 48.935894 -214.524082)
		(end 48.489362 -214.524082)
		(width 0.20066)
		(layer "F.Cu")
		(net "M_B_CPU1_SB_DQ<15>")
	)
	(segment
		(start 90.024966 -231.436164)
		(end 90.024966 -230.900478)
		(width 0.20066)
		(layer "F.Cu")
		(net "M_B_CPU1_SB_DQ<15>")
	)
	(segment
		(start 44.735242 -214.75573)
		(end 44.38142 -214.75573)
		(width 0.20066)
		(layer "F.Cu")
		(net "M_B_CPU1_SB_DQ<15>")
	)
	(segment
		(start 44.112942 -214.316564)
		(end 42.415714 -214.316564)
		(width 0.20066)
		(layer "F.Cu")
		(net "M_B_CPU1_SB_DQ<15>")
	)
	(segment
		(start 48.489362 -214.524082)
		(end 48.277526 -214.312246)
		(width 0.20066)
		(layer "F.Cu")
		(net "M_B_CPU1_SB_DQ<15>")
	)
	(segment
		(start 47.60468 -214.741506)
		(end 47.060358 -214.741506)
		(width 0.20066)
		(layer "F.Cu")
		(net "M_B_CPU1_SB_DQ<15>")
	)
	(segment
		(start 44.238926 -214.442548)
		(end 44.112942 -214.316564)
		(width 0.20066)
		(layer "F.Cu")
		(net "M_B_CPU1_SB_DQ<15>")
	)
	(segment
		(start 44.38142 -214.75573)
		(end 44.238926 -214.613236)
		(width 0.20066)
		(layer "F.Cu")
		(net "M_B_CPU1_SB_DQ<15>")
	)
	(segment
		(start 44.987464 -214.741506)
		(end 44.749466 -214.741506)
		(width 0.101854)
		(layer "F.Cu")
		(net "M_B_CPU1_SB_DQ<15>")
	)
	(segment
		(start 47.753778 -214.592408)
		(end 47.60468 -214.741506)
		(width 0.20066)
		(layer "F.Cu")
		(net "M_B_CPU1_SB_DQ<15>")
	)
	(segment
		(start 44.238926 -214.613236)
		(end 44.238926 -214.442548)
		(width 0.20066)
		(layer "F.Cu")
		(net "M_B_CPU1_SB_DQ<15>")
	)
	(segment
		(start 47.060358 -214.741506)
		(end 44.987464 -214.741506)
		(width 0.1016)
		(layer "F.Cu")
		(net "M_B_CPU1_SB_DQ<15>")
	)
	(segment
		(start 51.064414 -214.316564)
		(end 49.959514 -214.316564)
		(width 0.20066)
		(layer "F.Cu")
		(net "M_B_CPU1_SB_DQ<15>")
	)
	(segment
		(start 47.882302 -214.312246)
		(end 47.753778 -214.44077)
		(width 0.20066)
		(layer "F.Cu")
		(net "M_B_CPU1_SB_DQ<15>")
	)
	(segment
		(start 59.362086 -214.563706)
		(end 59.362086 -214.052404)
		(width 0.18288)
		(layer "In2.Cu")
		(net "M_B_CPU1_SB_DQ<15>")
	)
	(segment
		(start 54.906418 -214.745316)
		(end 52.619148 -214.745316)
		(width 0.18288)
		(layer "In2.Cu")
		(net "M_B_CPU1_SB_DQ<15>")
	)
	(segment
		(start 59.555126 -214.756746)
		(end 59.362086 -214.563706)
		(width 0.18288)
		(layer "In2.Cu")
		(net "M_B_CPU1_SB_DQ<15>")
	)
	(segment
		(start 84.95538 -229.235)
		(end 83.843368 -228.122988)
		(width 0.18288)
		(layer "In2.Cu")
		(net "M_B_CPU1_SB_DQ<15>")
	)
	(segment
		(start 68.164964 -214.216234)
		(end 67.844924 -214.216234)
		(width 0.18288)
		(layer "In2.Cu")
		(net "M_B_CPU1_SB_DQ<15>")
	)
	(segment
		(start 86.548214 -230.41102)
		(end 86.533482 -230.402384)
		(width 0.088646)
		(layer "In2.Cu")
		(net "M_B_CPU1_SB_DQ<15>")
	)
	(segment
		(start 59.169046 -213.859364)
		(end 58.849006 -213.859364)
		(width 0.18288)
		(layer "In2.Cu")
		(net "M_B_CPU1_SB_DQ<15>")
	)
	(segment
		(start 61.414914 -214.601552)
		(end 61.414914 -214.047832)
		(width 0.18288)
		(layer "In2.Cu")
		(net "M_B_CPU1_SB_DQ<15>")
	)
	(segment
		(start 58.403744 -214.773256)
		(end 56.576976 -214.773256)
		(width 0.18288)
		(layer "In2.Cu")
		(net "M_B_CPU1_SB_DQ<15>")
	)
	(segment
		(start 62.632082 -214.761572)
		(end 61.574934 -214.761572)
		(width 0.18288)
		(layer "In2.Cu")
		(net "M_B_CPU1_SB_DQ<15>")
	)
	(segment
		(start 60.47486 -214.047832)
		(end 60.47486 -214.571326)
		(width 0.18288)
		(layer "In2.Cu")
		(net "M_B_CPU1_SB_DQ<15>")
	)
	(segment
		(start 67.651884 -213.662768)
		(end 67.458844 -213.469728)
		(width 0.18288)
		(layer "In2.Cu")
		(net "M_B_CPU1_SB_DQ<15>")
	)
	(segment
		(start 68.358004 -213.754462)
		(end 68.358004 -214.023194)
		(width 0.18288)
		(layer "In2.Cu")
		(net "M_B_CPU1_SB_DQ<15>")
	)
	(segment
		(start 83.423506 -228.122988)
		(end 68.86194 -213.561422)
		(width 0.18288)
		(layer "In2.Cu")
		(net "M_B_CPU1_SB_DQ<15>")
	)
	(segment
		(start 60.675012 -213.84768)
		(end 60.47486 -214.047832)
		(width 0.18288)
		(layer "In2.Cu")
		(net "M_B_CPU1_SB_DQ<15>")
	)
	(segment
		(start 83.843368 -228.122988)
		(end 83.423506 -228.122988)
		(width 0.18288)
		(layer "In2.Cu")
		(net "M_B_CPU1_SB_DQ<15>")
	)
	(segment
		(start 66.945764 -214.023194)
		(end 66.752724 -214.216234)
		(width 0.18288)
		(layer "In2.Cu")
		(net "M_B_CPU1_SB_DQ<15>")
	)
	(segment
		(start 51.637184 -214.889334)
		(end 51.064414 -214.316564)
		(width 0.18288)
		(layer "In2.Cu")
		(net "M_B_CPU1_SB_DQ<15>")
	)
	(segment
		(start 55.90667 -214.10295)
		(end 55.548784 -214.10295)
		(width 0.18288)
		(layer "In2.Cu")
		(net "M_B_CPU1_SB_DQ<15>")
	)
	(segment
		(start 66.752724 -214.216234)
		(end 66.204338 -214.216234)
		(width 0.18288)
		(layer "In2.Cu")
		(net "M_B_CPU1_SB_DQ<15>")
	)
	(segment
		(start 61.414914 -214.047832)
		(end 61.214762 -213.84768)
		(width 0.18288)
		(layer "In2.Cu")
		(net "M_B_CPU1_SB_DQ<15>")
	)
	(segment
		(start 87.488014 -230.41102)
		(end 87.473282 -230.402384)
		(width 0.088646)
		(layer "In2.Cu")
		(net "M_B_CPU1_SB_DQ<15>")
	)
	(segment
		(start 58.849006 -213.859364)
		(end 58.655966 -214.052404)
		(width 0.18288)
		(layer "In2.Cu")
		(net "M_B_CPU1_SB_DQ<15>")
	)
	(segment
		(start 67.844924 -214.216234)
		(end 67.651884 -214.023194)
		(width 0.18288)
		(layer "In2.Cu")
		(net "M_B_CPU1_SB_DQ<15>")
	)
	(segment
		(start 87.862664 -230.41102)
		(end 87.86241 -230.41102)
		(width 0.088646)
		(layer "In2.Cu")
		(net "M_B_CPU1_SB_DQ<15>")
	)
	(segment
		(start 85.096096 -229.908354)
		(end 84.95538 -229.767638)
		(width 0.18288)
		(layer "In2.Cu")
		(net "M_B_CPU1_SB_DQ<15>")
	)
	(segment
		(start 58.655966 -214.052404)
		(end 58.655966 -214.521034)
		(width 0.18288)
		(layer "In2.Cu")
		(net "M_B_CPU1_SB_DQ<15>")
	)
	(segment
		(start 66.945764 -213.662768)
		(end 66.945764 -214.023194)
		(width 0.18288)
		(layer "In2.Cu")
		(net "M_B_CPU1_SB_DQ<15>")
	)
	(segment
		(start 68.86194 -213.561422)
		(end 68.551044 -213.561422)
		(width 0.18288)
		(layer "In2.Cu")
		(net "M_B_CPU1_SB_DQ<15>")
	)
	(segment
		(start 85.567266 -230.379524)
		(end 85.096096 -229.908354)
		(width 0.088646)
		(layer "In2.Cu")
		(net "M_B_CPU1_SB_DQ<15>")
	)
	(segment
		(start 63.4873 -213.906354)
		(end 62.632082 -214.761572)
		(width 0.18288)
		(layer "In2.Cu")
		(net "M_B_CPU1_SB_DQ<15>")
	)
	(segment
		(start 56.576976 -214.773256)
		(end 55.90667 -214.10295)
		(width 0.18288)
		(layer "In2.Cu")
		(net "M_B_CPU1_SB_DQ<15>")
	)
	(segment
		(start 52.47513 -214.889334)
		(end 51.637184 -214.889334)
		(width 0.18288)
		(layer "In2.Cu")
		(net "M_B_CPU1_SB_DQ<15>")
	)
	(segment
		(start 67.651884 -214.023194)
		(end 67.651884 -213.662768)
		(width 0.18288)
		(layer "In2.Cu")
		(net "M_B_CPU1_SB_DQ<15>")
	)
	(segment
		(start 52.619148 -214.745316)
		(end 52.47513 -214.889334)
		(width 0.18288)
		(layer "In2.Cu")
		(net "M_B_CPU1_SB_DQ<15>")
	)
	(segment
		(start 55.548784 -214.10295)
		(end 54.906418 -214.745316)
		(width 0.18288)
		(layer "In2.Cu")
		(net "M_B_CPU1_SB_DQ<15>")
	)
	(segment
		(start 89.02065 -230.484426)
		(end 88.701626 -230.484426)
		(width 0.088646)
		(layer "In2.Cu")
		(net "M_B_CPU1_SB_DQ<15>")
	)
	(segment
		(start 60.28944 -214.756746)
		(end 59.555126 -214.756746)
		(width 0.18288)
		(layer "In2.Cu")
		(net "M_B_CPU1_SB_DQ<15>")
	)
	(segment
		(start 66.204338 -214.216234)
		(end 65.894458 -213.906354)
		(width 0.18288)
		(layer "In2.Cu")
		(net "M_B_CPU1_SB_DQ<15>")
	)
	(segment
		(start 67.458844 -213.469728)
		(end 67.138804 -213.469728)
		(width 0.18288)
		(layer "In2.Cu")
		(net "M_B_CPU1_SB_DQ<15>")
	)
	(segment
		(start 68.358004 -214.023194)
		(end 68.164964 -214.216234)
		(width 0.18288)
		(layer "In2.Cu")
		(net "M_B_CPU1_SB_DQ<15>")
	)
	(segment
		(start 67.138804 -213.469728)
		(end 66.945764 -213.662768)
		(width 0.18288)
		(layer "In2.Cu")
		(net "M_B_CPU1_SB_DQ<15>")
	)
	(segment
		(start 59.362086 -214.052404)
		(end 59.169046 -213.859364)
		(width 0.18288)
		(layer "In2.Cu")
		(net "M_B_CPU1_SB_DQ<15>")
	)
	(segment
		(start 68.551044 -213.561422)
		(end 68.358004 -213.754462)
		(width 0.18288)
		(layer "In2.Cu")
		(net "M_B_CPU1_SB_DQ<15>")
	)
	(segment
		(start 58.655966 -214.521034)
		(end 58.403744 -214.773256)
		(width 0.18288)
		(layer "In2.Cu")
		(net "M_B_CPU1_SB_DQ<15>")
	)
	(segment
		(start 61.574934 -214.761572)
		(end 61.414914 -214.601552)
		(width 0.18288)
		(layer "In2.Cu")
		(net "M_B_CPU1_SB_DQ<15>")
	)
	(segment
		(start 84.95538 -229.767638)
		(end 84.95538 -229.235)
		(width 0.18288)
		(layer "In2.Cu")
		(net "M_B_CPU1_SB_DQ<15>")
	)
	(segment
		(start 60.47486 -214.571326)
		(end 60.28944 -214.756746)
		(width 0.18288)
		(layer "In2.Cu")
		(net "M_B_CPU1_SB_DQ<15>")
	)
	(segment
		(start 65.894458 -213.906354)
		(end 63.4873 -213.906354)
		(width 0.18288)
		(layer "In2.Cu")
		(net "M_B_CPU1_SB_DQ<15>")
	)
	(segment
		(start 61.214762 -213.84768)
		(end 60.675012 -213.84768)
		(width 0.18288)
		(layer "In2.Cu")
		(net "M_B_CPU1_SB_DQ<15>")
	)
	(arc
		(start 88.701626 -230.484426)
		(mid 88.559881 -230.465764)
		(end 88.427814 -230.41102)
		(width 0.088646)
		(layer "In2.Cu")
		(net "M_B_CPU1_SB_DQ<15>")
	)
	(arc
		(start 87.473282 -230.402384)
		(mid 87.196807 -230.335064)
		(end 86.92261 -230.41102)
		(width 0.088646)
		(layer "In2.Cu")
		(net "M_B_CPU1_SB_DQ<15>")
	)
	(arc
		(start 88.427814 -230.41102)
		(mid 88.145256 -230.335371)
		(end 87.862664 -230.41102)
		(width 0.088646)
		(layer "In2.Cu")
		(net "M_B_CPU1_SB_DQ<15>")
	)
	(arc
		(start 86.92261 -230.41102)
		(mid 86.735412 -230.461163)
		(end 86.548214 -230.41102)
		(width 0.088646)
		(layer "In2.Cu")
		(net "M_B_CPU1_SB_DQ<15>")
	)
	(arc
		(start 90.024966 -230.900478)
		(mid 89.564182 -230.592592)
		(end 89.02065 -230.484426)
		(width 0.088646)
		(layer "In2.Cu")
		(net "M_B_CPU1_SB_DQ<15>")
	)
	(arc
		(start 87.86241 -230.41102)
		(mid 87.675212 -230.461163)
		(end 87.488014 -230.41102)
		(width 0.088646)
		(layer "In2.Cu")
		(net "M_B_CPU1_SB_DQ<15>")
	)
	(arc
		(start 85.608414 -230.41102)
		(mid 85.5868 -230.39663)
		(end 85.567266 -230.379524)
		(width 0.088646)
		(layer "In2.Cu")
		(net "M_B_CPU1_SB_DQ<15>")
	)
	(arc
		(start 86.533482 -230.402384)
		(mid 86.257007 -230.335064)
		(end 85.98281 -230.41102)
		(width 0.088646)
		(layer "In2.Cu")
		(net "M_B_CPU1_SB_DQ<15>")
	)
	(arc
		(start 85.98281 -230.41102)
		(mid 85.795612 -230.461163)
		(end 85.608414 -230.41102)
		(width 0.088646)
		(layer "In2.Cu")
		(net "M_B_CPU1_SB_DQ<15>")
	)
	(segment
		(start 51.064414 -216.016586)
		(end 49.959514 -216.016586)
		(width 0.20066)
		(layer "F.Cu")
		(net "M_B_CPU1_SB_DQ<14>")
	)
	(segment
		(start 48.432974 -216.228422)
		(end 48.004476 -216.228422)
		(width 0.20066)
		(layer "F.Cu")
		(net "M_B_CPU1_SB_DQ<14>")
	)
	(segment
		(start 48.64481 -216.016586)
		(end 48.432974 -216.228422)
		(width 0.20066)
		(layer "F.Cu")
		(net "M_B_CPU1_SB_DQ<14>")
	)
	(segment
		(start 48.004476 -216.228422)
		(end 47.83709 -216.061036)
		(width 0.20066)
		(layer "F.Cu")
		(net "M_B_CPU1_SB_DQ<14>")
	)
	(segment
		(start 90.494866 -232.250488)
		(end 90.494612 -232.250234)
		(width 0.20066)
		(layer "F.Cu")
		(net "M_B_CPU1_SB_DQ<14>")
	)
	(segment
		(start 43.562778 -216.016586)
		(end 42.415714 -216.016586)
		(width 0.20066)
		(layer "F.Cu")
		(net "M_B_CPU1_SB_DQ<14>")
	)
	(segment
		(start 90.494612 -232.250234)
		(end 90.494612 -231.714548)
		(width 0.20066)
		(layer "F.Cu")
		(net "M_B_CPU1_SB_DQ<14>")
	)
	(segment
		(start 49.959514 -216.016586)
		(end 48.64481 -216.016586)
		(width 0.20066)
		(layer "F.Cu")
		(net "M_B_CPU1_SB_DQ<14>")
	)
	(segment
		(start 47.060358 -215.591644)
		(end 45.000418 -215.591644)
		(width 0.1016)
		(layer "F.Cu")
		(net "M_B_CPU1_SB_DQ<14>")
	)
	(segment
		(start 44.735242 -215.581484)
		(end 43.99788 -215.581484)
		(width 0.20066)
		(layer "F.Cu")
		(net "M_B_CPU1_SB_DQ<14>")
	)
	(segment
		(start 44.745402 -215.591644)
		(end 44.735242 -215.581484)
		(width 0.101854)
		(layer "F.Cu")
		(net "M_B_CPU1_SB_DQ<14>")
	)
	(segment
		(start 43.99788 -215.581484)
		(end 43.562778 -216.016586)
		(width 0.20066)
		(layer "F.Cu")
		(net "M_B_CPU1_SB_DQ<14>")
	)
	(segment
		(start 47.83709 -216.061036)
		(end 47.83709 -215.735408)
		(width 0.20066)
		(layer "F.Cu")
		(net "M_B_CPU1_SB_DQ<14>")
	)
	(segment
		(start 45.000418 -215.591644)
		(end 44.745402 -215.591644)
		(width 0.101854)
		(layer "F.Cu")
		(net "M_B_CPU1_SB_DQ<14>")
	)
	(segment
		(start 47.693326 -215.591644)
		(end 47.060358 -215.591644)
		(width 0.20066)
		(layer "F.Cu")
		(net "M_B_CPU1_SB_DQ<14>")
	)
	(segment
		(start 47.83709 -215.735408)
		(end 47.693326 -215.591644)
		(width 0.20066)
		(layer "F.Cu")
		(net "M_B_CPU1_SB_DQ<14>")
	)
	(segment
		(start 69.35343 -216.397586)
		(end 69.16039 -216.204546)
		(width 0.18288)
		(layer "In2.Cu")
		(net "M_B_CPU1_SB_DQ<14>")
	)
	(segment
		(start 88.902286 -231.22763)
		(end 88.897714 -231.22509)
		(width 0.088646)
		(layer "In2.Cu")
		(net "M_B_CPU1_SB_DQ<14>")
	)
	(segment
		(start 55.25643 -215.803226)
		(end 55.06339 -215.996266)
		(width 0.18288)
		(layer "In2.Cu")
		(net "M_B_CPU1_SB_DQ<14>")
	)
	(segment
		(start 55.76951 -216.219532)
		(end 55.76951 -215.996266)
		(width 0.18288)
		(layer "In2.Cu")
		(net "M_B_CPU1_SB_DQ<14>")
	)
	(segment
		(start 66.765932 -215.257888)
		(end 66.424048 -215.599772)
		(width 0.18288)
		(layer "In2.Cu")
		(net "M_B_CPU1_SB_DQ<14>")
	)
	(segment
		(start 70.10781 -216.277698)
		(end 69.834506 -216.277698)
		(width 0.18288)
		(layer "In2.Cu")
		(net "M_B_CPU1_SB_DQ<14>")
	)
	(segment
		(start 69.834506 -216.277698)
		(end 69.714618 -216.397586)
		(width 0.18288)
		(layer "In2.Cu")
		(net "M_B_CPU1_SB_DQ<14>")
	)
	(segment
		(start 55.06339 -215.996266)
		(end 55.06339 -216.526872)
		(width 0.18288)
		(layer "In2.Cu")
		(net "M_B_CPU1_SB_DQ<14>")
	)
	(segment
		(start 84.570062 -230.925878)
		(end 84.32419 -230.680006)
		(width 0.088646)
		(layer "In2.Cu")
		(net "M_B_CPU1_SB_DQ<14>")
	)
	(segment
		(start 58.888376 -216.248488)
		(end 58.490866 -216.248488)
		(width 0.18288)
		(layer "In2.Cu")
		(net "M_B_CPU1_SB_DQ<14>")
	)
	(segment
		(start 54.06009 -216.22258)
		(end 52.762658 -216.22258)
		(width 0.18288)
		(layer "In2.Cu")
		(net "M_B_CPU1_SB_DQ<14>")
	)
	(segment
		(start 54.557422 -216.719912)
		(end 54.06009 -216.22258)
		(width 0.18288)
		(layer "In2.Cu")
		(net "M_B_CPU1_SB_DQ<14>")
	)
	(segment
		(start 85.06079 -231.165654)
		(end 84.821014 -230.925878)
		(width 0.088646)
		(layer "In2.Cu")
		(net "M_B_CPU1_SB_DQ<14>")
	)
	(segment
		(start 89.936574 -231.283002)
		(end 89.830148 -231.220772)
		(width 0.088646)
		(layer "In2.Cu")
		(net "M_B_CPU1_SB_DQ<14>")
	)
	(segment
		(start 57.971436 -216.767918)
		(end 56.93918 -216.767918)
		(width 0.18288)
		(layer "In2.Cu")
		(net "M_B_CPU1_SB_DQ<14>")
	)
	(segment
		(start 63.515494 -215.599772)
		(end 62.349888 -216.765378)
		(width 0.18288)
		(layer "In2.Cu")
		(net "M_B_CPU1_SB_DQ<14>")
	)
	(segment
		(start 84.32419 -230.680006)
		(end 79.57693 -225.932746)
		(width 0.18288)
		(layer "In2.Cu")
		(net "M_B_CPU1_SB_DQ<14>")
	)
	(segment
		(start 67.162426 -215.257888)
		(end 66.765932 -215.257888)
		(width 0.18288)
		(layer "In2.Cu")
		(net "M_B_CPU1_SB_DQ<14>")
	)
	(segment
		(start 60.13577 -216.364566)
		(end 59.730386 -216.76995)
		(width 0.18288)
		(layer "In2.Cu")
		(net "M_B_CPU1_SB_DQ<14>")
	)
	(segment
		(start 69.16039 -215.450928)
		(end 68.96735 -215.257888)
		(width 0.18288)
		(layer "In2.Cu")
		(net "M_B_CPU1_SB_DQ<14>")
	)
	(segment
		(start 58.490866 -216.248488)
		(end 57.971436 -216.767918)
		(width 0.18288)
		(layer "In2.Cu")
		(net "M_B_CPU1_SB_DQ<14>")
	)
	(segment
		(start 67.355466 -216.204546)
		(end 67.355466 -215.450928)
		(width 0.18288)
		(layer "In2.Cu")
		(net "M_B_CPU1_SB_DQ<14>")
	)
	(segment
		(start 55.57647 -215.803226)
		(end 55.25643 -215.803226)
		(width 0.18288)
		(layer "In2.Cu")
		(net "M_B_CPU1_SB_DQ<14>")
	)
	(segment
		(start 52.496212 -216.489026)
		(end 51.536854 -216.489026)
		(width 0.18288)
		(layer "In2.Cu")
		(net "M_B_CPU1_SB_DQ<14>")
	)
	(segment
		(start 67.355466 -215.450928)
		(end 67.162426 -215.257888)
		(width 0.18288)
		(layer "In2.Cu")
		(net "M_B_CPU1_SB_DQ<14>")
	)
	(segment
		(start 66.424048 -215.599772)
		(end 63.515494 -215.599772)
		(width 0.18288)
		(layer "In2.Cu")
		(net "M_B_CPU1_SB_DQ<14>")
	)
	(segment
		(start 54.87035 -216.719912)
		(end 54.557422 -216.719912)
		(width 0.18288)
		(layer "In2.Cu")
		(net "M_B_CPU1_SB_DQ<14>")
	)
	(segment
		(start 90.494612 -231.714548)
		(end 90.494358 -231.714294)
		(width 0.088646)
		(layer "In2.Cu")
		(net "M_B_CPU1_SB_DQ<14>")
	)
	(segment
		(start 69.16039 -216.204546)
		(end 69.16039 -215.450928)
		(width 0.18288)
		(layer "In2.Cu")
		(net "M_B_CPU1_SB_DQ<14>")
	)
	(segment
		(start 87.957914 -231.22509)
		(end 87.958168 -231.224836)
		(width 0.088646)
		(layer "In2.Cu")
		(net "M_B_CPU1_SB_DQ<14>")
	)
	(segment
		(start 56.583834 -216.412572)
		(end 55.96255 -216.412572)
		(width 0.18288)
		(layer "In2.Cu")
		(net "M_B_CPU1_SB_DQ<14>")
	)
	(segment
		(start 55.06339 -216.526872)
		(end 54.87035 -216.719912)
		(width 0.18288)
		(layer "In2.Cu")
		(net "M_B_CPU1_SB_DQ<14>")
	)
	(segment
		(start 55.76951 -215.996266)
		(end 55.57647 -215.803226)
		(width 0.18288)
		(layer "In2.Cu")
		(net "M_B_CPU1_SB_DQ<14>")
	)
	(segment
		(start 56.93918 -216.767918)
		(end 56.583834 -216.412572)
		(width 0.18288)
		(layer "In2.Cu")
		(net "M_B_CPU1_SB_DQ<14>")
	)
	(segment
		(start 68.223384 -216.204546)
		(end 68.030344 -216.397586)
		(width 0.18288)
		(layer "In2.Cu")
		(net "M_B_CPU1_SB_DQ<14>")
	)
	(segment
		(start 69.714618 -216.397586)
		(end 69.35343 -216.397586)
		(width 0.18288)
		(layer "In2.Cu")
		(net "M_B_CPU1_SB_DQ<14>")
	)
	(segment
		(start 59.409838 -216.76995)
		(end 58.888376 -216.248488)
		(width 0.18288)
		(layer "In2.Cu")
		(net "M_B_CPU1_SB_DQ<14>")
	)
	(segment
		(start 59.730386 -216.76995)
		(end 59.409838 -216.76995)
		(width 0.18288)
		(layer "In2.Cu")
		(net "M_B_CPU1_SB_DQ<14>")
	)
	(segment
		(start 68.416424 -215.257888)
		(end 68.223384 -215.450928)
		(width 0.18288)
		(layer "In2.Cu")
		(net "M_B_CPU1_SB_DQ<14>")
	)
	(segment
		(start 68.030344 -216.397586)
		(end 67.548506 -216.397586)
		(width 0.18288)
		(layer "In2.Cu")
		(net "M_B_CPU1_SB_DQ<14>")
	)
	(segment
		(start 88.897714 -231.22509)
		(end 88.893142 -231.222296)
		(width 0.088646)
		(layer "In2.Cu")
		(net "M_B_CPU1_SB_DQ<14>")
	)
	(segment
		(start 84.821014 -230.925878)
		(end 84.570062 -230.925878)
		(width 0.088646)
		(layer "In2.Cu")
		(net "M_B_CPU1_SB_DQ<14>")
	)
	(segment
		(start 55.96255 -216.412572)
		(end 55.76951 -216.219532)
		(width 0.18288)
		(layer "In2.Cu")
		(net "M_B_CPU1_SB_DQ<14>")
	)
	(segment
		(start 68.96735 -215.257888)
		(end 68.416424 -215.257888)
		(width 0.18288)
		(layer "In2.Cu")
		(net "M_B_CPU1_SB_DQ<14>")
	)
	(segment
		(start 79.57693 -225.932746)
		(end 79.57693 -225.746818)
		(width 0.18288)
		(layer "In2.Cu")
		(net "M_B_CPU1_SB_DQ<14>")
	)
	(segment
		(start 61.675772 -216.364566)
		(end 60.13577 -216.364566)
		(width 0.18288)
		(layer "In2.Cu")
		(net "M_B_CPU1_SB_DQ<14>")
	)
	(segment
		(start 68.223384 -215.450928)
		(end 68.223384 -216.204546)
		(width 0.18288)
		(layer "In2.Cu")
		(net "M_B_CPU1_SB_DQ<14>")
	)
	(segment
		(start 79.57693 -225.746818)
		(end 70.10781 -216.277698)
		(width 0.18288)
		(layer "In2.Cu")
		(net "M_B_CPU1_SB_DQ<14>")
	)
	(segment
		(start 51.536854 -216.489026)
		(end 51.064414 -216.016586)
		(width 0.18288)
		(layer "In2.Cu")
		(net "M_B_CPU1_SB_DQ<14>")
	)
	(segment
		(start 67.548506 -216.397586)
		(end 67.355466 -216.204546)
		(width 0.18288)
		(layer "In2.Cu")
		(net "M_B_CPU1_SB_DQ<14>")
	)
	(segment
		(start 62.076584 -216.765378)
		(end 61.675772 -216.364566)
		(width 0.18288)
		(layer "In2.Cu")
		(net "M_B_CPU1_SB_DQ<14>")
	)
	(segment
		(start 52.762658 -216.22258)
		(end 52.496212 -216.489026)
		(width 0.18288)
		(layer "In2.Cu")
		(net "M_B_CPU1_SB_DQ<14>")
	)
	(segment
		(start 62.349888 -216.765378)
		(end 62.076584 -216.765378)
		(width 0.18288)
		(layer "In2.Cu")
		(net "M_B_CPU1_SB_DQ<14>")
	)
	(arc
		(start 87.392764 -231.224836)
		(mid 87.205566 -231.274979)
		(end 87.018368 -231.224836)
		(width 0.088646)
		(layer "In2.Cu")
		(net "M_B_CPU1_SB_DQ<14>")
	)
	(arc
		(start 90.494358 -231.714294)
		(mid 90.229234 -231.480843)
		(end 89.936574 -231.283002)
		(width 0.088646)
		(layer "In2.Cu")
		(net "M_B_CPU1_SB_DQ<14>")
	)
	(arc
		(start 88.332564 -231.22509)
		(mid 88.145256 -231.275199)
		(end 87.957914 -231.22509)
		(width 0.088646)
		(layer "In2.Cu")
		(net "M_B_CPU1_SB_DQ<14>")
	)
	(arc
		(start 88.893142 -231.222296)
		(mid 88.612478 -231.149288)
		(end 88.332564 -231.22509)
		(width 0.088646)
		(layer "In2.Cu")
		(net "M_B_CPU1_SB_DQ<14>")
	)
	(arc
		(start 89.272364 -231.22509)
		(mid 89.08767 -231.275191)
		(end 88.902286 -231.22763)
		(width 0.088646)
		(layer "In2.Cu")
		(net "M_B_CPU1_SB_DQ<14>")
	)
	(arc
		(start 86.452964 -231.224836)
		(mid 86.265766 -231.274979)
		(end 86.078568 -231.224836)
		(width 0.088646)
		(layer "In2.Cu")
		(net "M_B_CPU1_SB_DQ<14>")
	)
	(arc
		(start 85.138768 -231.224836)
		(mid 85.097838 -231.197803)
		(end 85.06079 -231.165654)
		(width 0.088646)
		(layer "In2.Cu")
		(net "M_B_CPU1_SB_DQ<14>")
	)
	(arc
		(start 89.830148 -231.220772)
		(mid 89.550687 -231.149335)
		(end 89.272364 -231.22509)
		(width 0.088646)
		(layer "In2.Cu")
		(net "M_B_CPU1_SB_DQ<14>")
	)
	(arc
		(start 87.958168 -231.224836)
		(mid 87.675466 -231.149094)
		(end 87.392764 -231.224836)
		(width 0.088646)
		(layer "In2.Cu")
		(net "M_B_CPU1_SB_DQ<14>")
	)
	(arc
		(start 87.018368 -231.224836)
		(mid 86.735666 -231.149094)
		(end 86.452964 -231.224836)
		(width 0.088646)
		(layer "In2.Cu")
		(net "M_B_CPU1_SB_DQ<14>")
	)
	(arc
		(start 85.513164 -231.224836)
		(mid 85.325966 -231.274979)
		(end 85.138768 -231.224836)
		(width 0.088646)
		(layer "In2.Cu")
		(net "M_B_CPU1_SB_DQ<14>")
	)
	(arc
		(start 86.078568 -231.224836)
		(mid 85.795866 -231.149094)
		(end 85.513164 -231.224836)
		(width 0.088646)
		(layer "In2.Cu")
		(net "M_B_CPU1_SB_DQ<14>")
	)
	(segment
		(start 46.964346 -215.166702)
		(end 45.859446 -215.166702)
		(width 0.20066)
		(layer "F.Cu")
		(net "M_B_CPU1_SB_DQ<13>")
	)
	(segment
		(start 39.861236 -215.37803)
		(end 39.649908 -215.166702)
		(width 0.20066)
		(layer "F.Cu")
		(net "M_B_CPU1_SB_DQ<13>")
	)
	(segment
		(start 45.859446 -215.166702)
		(end 44.22013 -215.166702)
		(width 0.20066)
		(layer "F.Cu")
		(net "M_B_CPU1_SB_DQ<13>")
	)
	(segment
		(start 40.36568 -215.37803)
		(end 39.861236 -215.37803)
		(width 0.20066)
		(layer "F.Cu")
		(net "M_B_CPU1_SB_DQ<13>")
	)
	(segment
		(start 40.520112 -214.89543)
		(end 40.520112 -215.223598)
		(width 0.20066)
		(layer "F.Cu")
		(net "M_B_CPU1_SB_DQ<13>")
	)
	(segment
		(start 44.22013 -215.166702)
		(end 43.795188 -214.74176)
		(width 0.20066)
		(layer "F.Cu")
		(net "M_B_CPU1_SB_DQ<13>")
	)
	(segment
		(start 40.682672 -214.73287)
		(end 40.520112 -214.89543)
		(width 0.20066)
		(layer "F.Cu")
		(net "M_B_CPU1_SB_DQ<13>")
	)
	(segment
		(start 43.616626 -214.74176)
		(end 43.285918 -214.74176)
		(width 0.101854)
		(layer "F.Cu")
		(net "M_B_CPU1_SB_DQ<13>")
	)
	(segment
		(start 40.520112 -215.223598)
		(end 40.36568 -215.37803)
		(width 0.20066)
		(layer "F.Cu")
		(net "M_B_CPU1_SB_DQ<13>")
	)
	(segment
		(start 43.795188 -214.74176)
		(end 43.616626 -214.74176)
		(width 0.20066)
		(layer "F.Cu")
		(net "M_B_CPU1_SB_DQ<13>")
	)
	(segment
		(start 41.3004 -214.74176)
		(end 41.29151 -214.73287)
		(width 0.1016)
		(layer "F.Cu")
		(net "M_B_CPU1_SB_DQ<13>")
	)
	(segment
		(start 43.285918 -214.74176)
		(end 41.3004 -214.74176)
		(width 0.1016)
		(layer "F.Cu")
		(net "M_B_CPU1_SB_DQ<13>")
	)
	(segment
		(start 39.649908 -215.166702)
		(end 38.315646 -215.166702)
		(width 0.20066)
		(layer "F.Cu")
		(net "M_B_CPU1_SB_DQ<13>")
	)
	(segment
		(start 89.085166 -231.436164)
		(end 89.085166 -230.900478)
		(width 0.20066)
		(layer "F.Cu")
		(net "M_B_CPU1_SB_DQ<13>")
	)
	(segment
		(start 89.084912 -231.436418)
		(end 89.085166 -231.436164)
		(width 0.20066)
		(layer "F.Cu")
		(net "M_B_CPU1_SB_DQ<13>")
	)
	(segment
		(start 41.29151 -214.73287)
		(end 40.682672 -214.73287)
		(width 0.20066)
		(layer "F.Cu")
		(net "M_B_CPU1_SB_DQ<13>")
	)
	(segment
		(start 60.241688 -215.729312)
		(end 59.792362 -215.279986)
		(width 0.18288)
		(layer "In2.Cu")
		(net "M_B_CPU1_SB_DQ<13>")
	)
	(segment
		(start 87.957914 -230.57612)
		(end 87.958168 -230.57612)
		(width 0.088646)
		(layer "In2.Cu")
		(net "M_B_CPU1_SB_DQ<13>")
	)
	(segment
		(start 89.085166 -230.900478)
		(end 88.434926 -230.636826)
		(width 0.088646)
		(layer "In2.Cu")
		(net "M_B_CPU1_SB_DQ<13>")
	)
	(segment
		(start 50.26152 -215.048338)
		(end 49.59731 -215.048338)
		(width 0.18288)
		(layer "In2.Cu")
		(net "M_B_CPU1_SB_DQ<13>")
	)
	(segment
		(start 54.15153 -215.691974)
		(end 52.632102 -215.691974)
		(width 0.18288)
		(layer "In2.Cu")
		(net "M_B_CPU1_SB_DQ<13>")
	)
	(segment
		(start 63.399416 -214.730838)
		(end 62.84468 -215.285574)
		(width 0.18288)
		(layer "In2.Cu")
		(net "M_B_CPU1_SB_DQ<13>")
	)
	(segment
		(start 47.568358 -215.86825)
		(end 47.568358 -215.31961)
		(width 0.18288)
		(layer "In2.Cu")
		(net "M_B_CPU1_SB_DQ<13>")
	)
	(segment
		(start 56.54802 -215.710516)
		(end 56.27497 -215.710516)
		(width 0.18288)
		(layer "In2.Cu")
		(net "M_B_CPU1_SB_DQ<13>")
	)
	(segment
		(start 84.849462 -230.486458)
		(end 84.683854 -230.32085)
		(width 0.088646)
		(layer "In2.Cu")
		(net "M_B_CPU1_SB_DQ<13>")
	)
	(segment
		(start 48.584358 -216.06129)
		(end 47.761398 -216.06129)
		(width 0.18288)
		(layer "In2.Cu")
		(net "M_B_CPU1_SB_DQ<13>")
	)
	(segment
		(start 52.36337 -215.423242)
		(end 51.50231 -215.423242)
		(width 0.18288)
		(layer "In2.Cu")
		(net "M_B_CPU1_SB_DQ<13>")
	)
	(segment
		(start 64.638174 -214.995506)
		(end 64.373506 -214.730838)
		(width 0.18288)
		(layer "In2.Cu")
		(net "M_B_CPU1_SB_DQ<13>")
	)
	(segment
		(start 47.568358 -215.31961)
		(end 47.41545 -215.166702)
		(width 0.18288)
		(layer "In2.Cu")
		(net "M_B_CPU1_SB_DQ<13>")
	)
	(segment
		(start 86.467696 -230.584756)
		(end 86.452964 -230.57612)
		(width 0.088646)
		(layer "In2.Cu")
		(net "M_B_CPU1_SB_DQ<13>")
	)
	(segment
		(start 58.245248 -215.472264)
		(end 56.786272 -215.472264)
		(width 0.18288)
		(layer "In2.Cu")
		(net "M_B_CPU1_SB_DQ<13>")
	)
	(segment
		(start 80.084422 -225.535744)
		(end 69.279516 -214.730838)
		(width 0.18288)
		(layer "In2.Cu")
		(net "M_B_CPU1_SB_DQ<13>")
	)
	(segment
		(start 64.373506 -214.730838)
		(end 63.399416 -214.730838)
		(width 0.18288)
		(layer "In2.Cu")
		(net "M_B_CPU1_SB_DQ<13>")
	)
	(segment
		(start 62.84468 -215.285574)
		(end 62.092586 -215.285574)
		(width 0.18288)
		(layer "In2.Cu")
		(net "M_B_CPU1_SB_DQ<13>")
	)
	(segment
		(start 51.50231 -215.423242)
		(end 51.333908 -215.591644)
		(width 0.18288)
		(layer "In2.Cu")
		(net "M_B_CPU1_SB_DQ<13>")
	)
	(segment
		(start 85.527896 -230.584756)
		(end 85.513164 -230.57612)
		(width 0.088646)
		(layer "In2.Cu")
		(net "M_B_CPU1_SB_DQ<13>")
	)
	(segment
		(start 47.41545 -215.166702)
		(end 46.964346 -215.166702)
		(width 0.18288)
		(layer "In2.Cu")
		(net "M_B_CPU1_SB_DQ<13>")
	)
	(segment
		(start 62.092586 -215.285574)
		(end 61.648848 -215.729312)
		(width 0.18288)
		(layer "In2.Cu")
		(net "M_B_CPU1_SB_DQ<13>")
	)
	(segment
		(start 61.648848 -215.729312)
		(end 60.241688 -215.729312)
		(width 0.18288)
		(layer "In2.Cu")
		(net "M_B_CPU1_SB_DQ<13>")
	)
	(segment
		(start 65.077086 -214.995506)
		(end 64.638174 -214.995506)
		(width 0.18288)
		(layer "In2.Cu")
		(net "M_B_CPU1_SB_DQ<13>")
	)
	(segment
		(start 56.786272 -215.472264)
		(end 56.54802 -215.710516)
		(width 0.18288)
		(layer "In2.Cu")
		(net "M_B_CPU1_SB_DQ<13>")
	)
	(segment
		(start 59.393836 -215.279986)
		(end 58.9661 -215.707722)
		(width 0.18288)
		(layer "In2.Cu")
		(net "M_B_CPU1_SB_DQ<13>")
	)
	(segment
		(start 51.333908 -215.591644)
		(end 50.804826 -215.591644)
		(width 0.18288)
		(layer "In2.Cu")
		(net "M_B_CPU1_SB_DQ<13>")
	)
	(segment
		(start 52.632102 -215.691974)
		(end 52.36337 -215.423242)
		(width 0.18288)
		(layer "In2.Cu")
		(net "M_B_CPU1_SB_DQ<13>")
	)
	(segment
		(start 56.27497 -215.710516)
		(end 55.8419 -215.277446)
		(width 0.18288)
		(layer "In2.Cu")
		(net "M_B_CPU1_SB_DQ<13>")
	)
	(segment
		(start 80.084422 -225.721418)
		(end 80.084422 -225.535744)
		(width 0.18288)
		(layer "In2.Cu")
		(net "M_B_CPU1_SB_DQ<13>")
	)
	(segment
		(start 88.434926 -230.636826)
		(end 88.332564 -230.57612)
		(width 0.088646)
		(layer "In2.Cu")
		(net "M_B_CPU1_SB_DQ<13>")
	)
	(segment
		(start 50.804826 -215.591644)
		(end 50.26152 -215.048338)
		(width 0.18288)
		(layer "In2.Cu")
		(net "M_B_CPU1_SB_DQ<13>")
	)
	(segment
		(start 69.279516 -214.730838)
		(end 65.341754 -214.730838)
		(width 0.18288)
		(layer "In2.Cu")
		(net "M_B_CPU1_SB_DQ<13>")
	)
	(segment
		(start 58.480706 -215.707722)
		(end 58.245248 -215.472264)
		(width 0.18288)
		(layer "In2.Cu")
		(net "M_B_CPU1_SB_DQ<13>")
	)
	(segment
		(start 84.683854 -230.32085)
		(end 80.084422 -225.721418)
		(width 0.18288)
		(layer "In2.Cu")
		(net "M_B_CPU1_SB_DQ<13>")
	)
	(segment
		(start 59.792362 -215.279986)
		(end 59.393836 -215.279986)
		(width 0.18288)
		(layer "In2.Cu")
		(net "M_B_CPU1_SB_DQ<13>")
	)
	(segment
		(start 58.9661 -215.707722)
		(end 58.480706 -215.707722)
		(width 0.18288)
		(layer "In2.Cu")
		(net "M_B_CPU1_SB_DQ<13>")
	)
	(segment
		(start 47.761398 -216.06129)
		(end 47.568358 -215.86825)
		(width 0.18288)
		(layer "In2.Cu")
		(net "M_B_CPU1_SB_DQ<13>")
	)
	(segment
		(start 85.39607 -230.486458)
		(end 84.849462 -230.486458)
		(width 0.088646)
		(layer "In2.Cu")
		(net "M_B_CPU1_SB_DQ<13>")
	)
	(segment
		(start 54.566058 -215.277446)
		(end 54.15153 -215.691974)
		(width 0.18288)
		(layer "In2.Cu")
		(net "M_B_CPU1_SB_DQ<13>")
	)
	(segment
		(start 55.8419 -215.277446)
		(end 54.566058 -215.277446)
		(width 0.18288)
		(layer "In2.Cu")
		(net "M_B_CPU1_SB_DQ<13>")
	)
	(segment
		(start 49.59731 -215.048338)
		(end 48.584358 -216.06129)
		(width 0.18288)
		(layer "In2.Cu")
		(net "M_B_CPU1_SB_DQ<13>")
	)
	(segment
		(start 87.407496 -230.584756)
		(end 87.392764 -230.57612)
		(width 0.088646)
		(layer "In2.Cu")
		(net "M_B_CPU1_SB_DQ<13>")
	)
	(segment
		(start 65.341754 -214.730838)
		(end 65.077086 -214.995506)
		(width 0.18288)
		(layer "In2.Cu")
		(net "M_B_CPU1_SB_DQ<13>")
	)
	(arc
		(start 86.078568 -230.57612)
		(mid 85.804369 -230.651955)
		(end 85.527896 -230.584756)
		(width 0.088646)
		(layer "In2.Cu")
		(net "M_B_CPU1_SB_DQ<13>")
	)
	(arc
		(start 87.018368 -230.57612)
		(mid 86.744169 -230.651955)
		(end 86.467696 -230.584756)
		(width 0.088646)
		(layer "In2.Cu")
		(net "M_B_CPU1_SB_DQ<13>")
	)
	(arc
		(start 85.422232 -230.511096)
		(mid 85.408956 -230.498984)
		(end 85.39607 -230.486458)
		(width 0.088646)
		(layer "In2.Cu")
		(net "M_B_CPU1_SB_DQ<13>")
	)
	(arc
		(start 85.513164 -230.57612)
		(mid 85.466088 -230.54586)
		(end 85.422232 -230.511096)
		(width 0.088646)
		(layer "In2.Cu")
		(net "M_B_CPU1_SB_DQ<13>")
	)
	(arc
		(start 88.332564 -230.57612)
		(mid 88.145256 -230.525977)
		(end 87.957914 -230.57612)
		(width 0.088646)
		(layer "In2.Cu")
		(net "M_B_CPU1_SB_DQ<13>")
	)
	(arc
		(start 87.392764 -230.57612)
		(mid 87.205566 -230.525977)
		(end 87.018368 -230.57612)
		(width 0.088646)
		(layer "In2.Cu")
		(net "M_B_CPU1_SB_DQ<13>")
	)
	(arc
		(start 87.958168 -230.57612)
		(mid 87.683969 -230.651955)
		(end 87.407496 -230.584756)
		(width 0.088646)
		(layer "In2.Cu")
		(net "M_B_CPU1_SB_DQ<13>")
	)
	(arc
		(start 86.452964 -230.57612)
		(mid 86.265766 -230.525977)
		(end 86.078568 -230.57612)
		(width 0.088646)
		(layer "In2.Cu")
		(net "M_B_CPU1_SB_DQ<13>")
	)
	(segment
		(start 41.29151 -216.433654)
		(end 40.729662 -216.433654)
		(width 0.20066)
		(layer "F.Cu")
		(net "M_B_CPU1_SB_DQ<12>")
	)
	(segment
		(start 39.888668 -217.105484)
		(end 39.649908 -216.866724)
		(width 0.20066)
		(layer "F.Cu")
		(net "M_B_CPU1_SB_DQ<12>")
	)
	(segment
		(start 88.615266 -232.250488)
		(end 88.615012 -232.250234)
		(width 0.20066)
		(layer "F.Cu")
		(net "M_B_CPU1_SB_DQ<12>")
	)
	(segment
		(start 43.616626 -216.441782)
		(end 41.547542 -216.441782)
		(width 0.1016)
		(layer "F.Cu")
		(net "M_B_CPU1_SB_DQ<12>")
	)
	(segment
		(start 44.490386 -216.866724)
		(end 44.065444 -216.441782)
		(width 0.20066)
		(layer "F.Cu")
		(net "M_B_CPU1_SB_DQ<12>")
	)
	(segment
		(start 39.649908 -216.866724)
		(end 38.315646 -216.866724)
		(width 0.20066)
		(layer "F.Cu")
		(net "M_B_CPU1_SB_DQ<12>")
	)
	(segment
		(start 45.859446 -216.866724)
		(end 44.490386 -216.866724)
		(width 0.20066)
		(layer "F.Cu")
		(net "M_B_CPU1_SB_DQ<12>")
	)
	(segment
		(start 40.347392 -217.105484)
		(end 39.888668 -217.105484)
		(width 0.20066)
		(layer "F.Cu")
		(net "M_B_CPU1_SB_DQ<12>")
	)
	(segment
		(start 40.729662 -216.433654)
		(end 40.520112 -216.643204)
		(width 0.20066)
		(layer "F.Cu")
		(net "M_B_CPU1_SB_DQ<12>")
	)
	(segment
		(start 41.547542 -216.441782)
		(end 41.299638 -216.441782)
		(width 0.101854)
		(layer "F.Cu")
		(net "M_B_CPU1_SB_DQ<12>")
	)
	(segment
		(start 40.520112 -216.643204)
		(end 40.520112 -216.932764)
		(width 0.20066)
		(layer "F.Cu")
		(net "M_B_CPU1_SB_DQ<12>")
	)
	(segment
		(start 44.065444 -216.441782)
		(end 43.616626 -216.441782)
		(width 0.20066)
		(layer "F.Cu")
		(net "M_B_CPU1_SB_DQ<12>")
	)
	(segment
		(start 41.299638 -216.441782)
		(end 41.29151 -216.433654)
		(width 0.101854)
		(layer "F.Cu")
		(net "M_B_CPU1_SB_DQ<12>")
	)
	(segment
		(start 88.615012 -232.250234)
		(end 88.615012 -231.714548)
		(width 0.20066)
		(layer "F.Cu")
		(net "M_B_CPU1_SB_DQ<12>")
	)
	(segment
		(start 40.520112 -216.932764)
		(end 40.347392 -217.105484)
		(width 0.20066)
		(layer "F.Cu")
		(net "M_B_CPU1_SB_DQ<12>")
	)
	(segment
		(start 46.964346 -216.866724)
		(end 45.859446 -216.866724)
		(width 0.20066)
		(layer "F.Cu")
		(net "M_B_CPU1_SB_DQ<12>")
	)
	(segment
		(start 56.272684 -217.668602)
		(end 55.381652 -217.668602)
		(width 0.18288)
		(layer "In2.Cu")
		(net "M_B_CPU1_SB_DQ<12>")
	)
	(segment
		(start 83.96478 -231.039416)
		(end 79.040736 -226.115372)
		(width 0.18288)
		(layer "In2.Cu")
		(net "M_B_CPU1_SB_DQ<12>")
	)
	(segment
		(start 79.040736 -225.92919)
		(end 70.02653 -216.914984)
		(width 0.18288)
		(layer "In2.Cu")
		(net "M_B_CPU1_SB_DQ<12>")
	)
	(segment
		(start 87.922354 -231.424734)
		(end 87.862664 -231.39019)
		(width 0.088646)
		(layer "In2.Cu")
		(net "M_B_CPU1_SB_DQ<12>")
	)
	(segment
		(start 69.130418 -216.914984)
		(end 68.84924 -216.633806)
		(width 0.18288)
		(layer "In2.Cu")
		(net "M_B_CPU1_SB_DQ<12>")
	)
	(segment
		(start 66.1289 -216.210388)
		(end 65.914778 -216.42451)
		(width 0.18288)
		(layer "In2.Cu")
		(net "M_B_CPU1_SB_DQ<12>")
	)
	(segment
		(start 48.30064 -218.005914)
		(end 47.774098 -218.005914)
		(width 0.18288)
		(layer "In2.Cu")
		(net "M_B_CPU1_SB_DQ<12>")
	)
	(segment
		(start 54.9783 -217.26525)
		(end 52.521866 -217.26525)
		(width 0.18288)
		(layer "In2.Cu")
		(net "M_B_CPU1_SB_DQ<12>")
	)
	(segment
		(start 49.516792 -216.620852)
		(end 49.323752 -216.813892)
		(width 0.18288)
		(layer "In2.Cu")
		(net "M_B_CPU1_SB_DQ<12>")
	)
	(segment
		(start 84.92617 -231.300274)
		(end 84.877402 -231.251506)
		(width 0.088646)
		(layer "In2.Cu")
		(net "M_B_CPU1_SB_DQ<12>")
	)
	(segment
		(start 48.542702 -217.763852)
		(end 48.30064 -218.005914)
		(width 0.18288)
		(layer "In2.Cu")
		(net "M_B_CPU1_SB_DQ<12>")
	)
	(segment
		(start 66.616072 -216.210388)
		(end 66.1289 -216.210388)
		(width 0.18288)
		(layer "In2.Cu")
		(net "M_B_CPU1_SB_DQ<12>")
	)
	(segment
		(start 50.558446 -217.13063)
		(end 50.558446 -216.780872)
		(width 0.18288)
		(layer "In2.Cu")
		(net "M_B_CPU1_SB_DQ<12>")
	)
	(segment
		(start 50.398426 -216.620852)
		(end 49.516792 -216.620852)
		(width 0.18288)
		(layer "In2.Cu")
		(net "M_B_CPU1_SB_DQ<12>")
	)
	(segment
		(start 84.17687 -231.251506)
		(end 83.96478 -231.039416)
		(width 0.088646)
		(layer "In2.Cu")
		(net "M_B_CPU1_SB_DQ<12>")
	)
	(segment
		(start 66.809366 -216.670636)
		(end 66.809366 -216.403682)
		(width 0.18288)
		(layer "In2.Cu")
		(net "M_B_CPU1_SB_DQ<12>")
	)
	(segment
		(start 79.040736 -226.115372)
		(end 79.040736 -225.92919)
		(width 0.18288)
		(layer "In2.Cu")
		(net "M_B_CPU1_SB_DQ<12>")
	)
	(segment
		(start 52.30114 -217.044524)
		(end 51.529234 -217.044524)
		(width 0.18288)
		(layer "In2.Cu")
		(net "M_B_CPU1_SB_DQ<12>")
	)
	(segment
		(start 68.294758 -216.914984)
		(end 67.053714 -216.914984)
		(width 0.18288)
		(layer "In2.Cu")
		(net "M_B_CPU1_SB_DQ<12>")
	)
	(segment
		(start 65.914778 -216.42451)
		(end 63.493396 -216.42451)
		(width 0.18288)
		(layer "In2.Cu")
		(net "M_B_CPU1_SB_DQ<12>")
	)
	(segment
		(start 47.338996 -216.866724)
		(end 46.964346 -216.866724)
		(width 0.18288)
		(layer "In2.Cu")
		(net "M_B_CPU1_SB_DQ<12>")
	)
	(segment
		(start 59.05373 -217.561922)
		(end 58.648346 -217.561922)
		(width 0.18288)
		(layer "In2.Cu")
		(net "M_B_CPU1_SB_DQ<12>")
	)
	(segment
		(start 49.07153 -217.313256)
		(end 48.735742 -217.313256)
		(width 0.18288)
		(layer "In2.Cu")
		(net "M_B_CPU1_SB_DQ<12>")
	)
	(segment
		(start 52.521866 -217.26525)
		(end 52.30114 -217.044524)
		(width 0.18288)
		(layer "In2.Cu")
		(net "M_B_CPU1_SB_DQ<12>")
	)
	(segment
		(start 50.719482 -217.291666)
		(end 50.558446 -217.13063)
		(width 0.18288)
		(layer "In2.Cu")
		(net "M_B_CPU1_SB_DQ<12>")
	)
	(segment
		(start 68.575936 -216.633806)
		(end 68.294758 -216.914984)
		(width 0.18288)
		(layer "In2.Cu")
		(net "M_B_CPU1_SB_DQ<12>")
	)
	(segment
		(start 67.053714 -216.914984)
		(end 66.809366 -216.670636)
		(width 0.18288)
		(layer "In2.Cu")
		(net "M_B_CPU1_SB_DQ<12>")
	)
	(segment
		(start 47.532036 -217.059764)
		(end 47.338996 -216.866724)
		(width 0.18288)
		(layer "In2.Cu")
		(net "M_B_CPU1_SB_DQ<12>")
	)
	(segment
		(start 84.877402 -231.251506)
		(end 84.17687 -231.251506)
		(width 0.088646)
		(layer "In2.Cu")
		(net "M_B_CPU1_SB_DQ<12>")
	)
	(segment
		(start 56.651906 -217.28938)
		(end 56.272684 -217.668602)
		(width 0.18288)
		(layer "In2.Cu")
		(net "M_B_CPU1_SB_DQ<12>")
	)
	(segment
		(start 63.493396 -216.42451)
		(end 62.639956 -217.27795)
		(width 0.18288)
		(layer "In2.Cu")
		(net "M_B_CPU1_SB_DQ<12>")
	)
	(segment
		(start 58.375804 -217.28938)
		(end 56.651906 -217.28938)
		(width 0.18288)
		(layer "In2.Cu")
		(net "M_B_CPU1_SB_DQ<12>")
	)
	(segment
		(start 62.639956 -217.27795)
		(end 59.337702 -217.27795)
		(width 0.18288)
		(layer "In2.Cu")
		(net "M_B_CPU1_SB_DQ<12>")
	)
	(segment
		(start 88.252808 -231.616758)
		(end 87.922354 -231.424734)
		(width 0.088646)
		(layer "In2.Cu")
		(net "M_B_CPU1_SB_DQ<12>")
	)
	(segment
		(start 48.735742 -217.313256)
		(end 48.542702 -217.506296)
		(width 0.18288)
		(layer "In2.Cu")
		(net "M_B_CPU1_SB_DQ<12>")
	)
	(segment
		(start 50.558446 -216.780872)
		(end 50.398426 -216.620852)
		(width 0.18288)
		(layer "In2.Cu")
		(net "M_B_CPU1_SB_DQ<12>")
	)
	(segment
		(start 55.381652 -217.668602)
		(end 54.9783 -217.26525)
		(width 0.18288)
		(layer "In2.Cu")
		(net "M_B_CPU1_SB_DQ<12>")
	)
	(segment
		(start 49.323752 -216.813892)
		(end 49.323752 -217.061034)
		(width 0.18288)
		(layer "In2.Cu")
		(net "M_B_CPU1_SB_DQ<12>")
	)
	(segment
		(start 70.02653 -216.914984)
		(end 69.130418 -216.914984)
		(width 0.18288)
		(layer "In2.Cu")
		(net "M_B_CPU1_SB_DQ<12>")
	)
	(segment
		(start 47.532036 -217.763852)
		(end 47.532036 -217.059764)
		(width 0.18288)
		(layer "In2.Cu")
		(net "M_B_CPU1_SB_DQ<12>")
	)
	(segment
		(start 51.529234 -217.044524)
		(end 51.282092 -217.291666)
		(width 0.18288)
		(layer "In2.Cu")
		(net "M_B_CPU1_SB_DQ<12>")
	)
	(segment
		(start 68.84924 -216.633806)
		(end 68.575936 -216.633806)
		(width 0.18288)
		(layer "In2.Cu")
		(net "M_B_CPU1_SB_DQ<12>")
	)
	(segment
		(start 48.542702 -217.506296)
		(end 48.542702 -217.763852)
		(width 0.18288)
		(layer "In2.Cu")
		(net "M_B_CPU1_SB_DQ<12>")
	)
	(segment
		(start 58.648346 -217.561922)
		(end 58.375804 -217.28938)
		(width 0.18288)
		(layer "In2.Cu")
		(net "M_B_CPU1_SB_DQ<12>")
	)
	(segment
		(start 51.282092 -217.291666)
		(end 50.719482 -217.291666)
		(width 0.18288)
		(layer "In2.Cu")
		(net "M_B_CPU1_SB_DQ<12>")
	)
	(segment
		(start 47.774098 -218.005914)
		(end 47.532036 -217.763852)
		(width 0.18288)
		(layer "In2.Cu")
		(net "M_B_CPU1_SB_DQ<12>")
	)
	(segment
		(start 59.337702 -217.27795)
		(end 59.05373 -217.561922)
		(width 0.18288)
		(layer "In2.Cu")
		(net "M_B_CPU1_SB_DQ<12>")
	)
	(segment
		(start 49.323752 -217.061034)
		(end 49.07153 -217.313256)
		(width 0.18288)
		(layer "In2.Cu")
		(net "M_B_CPU1_SB_DQ<12>")
	)
	(segment
		(start 66.809366 -216.403682)
		(end 66.616072 -216.210388)
		(width 0.18288)
		(layer "In2.Cu")
		(net "M_B_CPU1_SB_DQ<12>")
	)
	(arc
		(start 85.983064 -231.39019)
		(mid 85.795866 -231.340047)
		(end 85.608668 -231.39019)
		(width 0.088646)
		(layer "In2.Cu")
		(net "M_B_CPU1_SB_DQ<12>")
	)
	(arc
		(start 85.608668 -231.39019)
		(mid 85.325966 -231.465932)
		(end 85.043264 -231.39019)
		(width 0.088646)
		(layer "In2.Cu")
		(net "M_B_CPU1_SB_DQ<12>")
	)
	(arc
		(start 85.043264 -231.39019)
		(mid 84.981769 -231.349071)
		(end 84.92617 -231.300274)
		(width 0.088646)
		(layer "In2.Cu")
		(net "M_B_CPU1_SB_DQ<12>")
	)
	(arc
		(start 86.922864 -231.39019)
		(mid 86.735666 -231.340047)
		(end 86.548468 -231.39019)
		(width 0.088646)
		(layer "In2.Cu")
		(net "M_B_CPU1_SB_DQ<12>")
	)
	(arc
		(start 86.548468 -231.39019)
		(mid 86.265766 -231.465932)
		(end 85.983064 -231.39019)
		(width 0.088646)
		(layer "In2.Cu")
		(net "M_B_CPU1_SB_DQ<12>")
	)
	(arc
		(start 87.488268 -231.39019)
		(mid 87.205566 -231.465932)
		(end 86.922864 -231.39019)
		(width 0.088646)
		(layer "In2.Cu")
		(net "M_B_CPU1_SB_DQ<12>")
	)
	(arc
		(start 87.862664 -231.39019)
		(mid 87.675466 -231.340047)
		(end 87.488268 -231.39019)
		(width 0.088646)
		(layer "In2.Cu")
		(net "M_B_CPU1_SB_DQ<12>")
	)
	(arc
		(start 88.615012 -231.714548)
		(mid 88.42743 -231.689645)
		(end 88.252808 -231.616758)
		(width 0.088646)
		(layer "In2.Cu")
		(net "M_B_CPU1_SB_DQ<12>")
	)
	(segment
		(start 49.959514 -220.266768)
		(end 49.143412 -220.266768)
		(width 0.20066)
		(layer "F.Cu")
		(net "M_B_CPU1_SB_DQ<11>")
	)
	(segment
		(start 49.143412 -220.266768)
		(end 48.935894 -220.474286)
		(width 0.20066)
		(layer "F.Cu")
		(net "M_B_CPU1_SB_DQ<11>")
	)
	(segment
		(start 47.060358 -220.69171)
		(end 44.987464 -220.69171)
		(width 0.1016)
		(layer "F.Cu")
		(net "M_B_CPU1_SB_DQ<11>")
	)
	(segment
		(start 44.735242 -220.705934)
		(end 44.38142 -220.705934)
		(width 0.20066)
		(layer "F.Cu")
		(net "M_B_CPU1_SB_DQ<11>")
	)
	(segment
		(start 48.277526 -220.26245)
		(end 47.882302 -220.26245)
		(width 0.20066)
		(layer "F.Cu")
		(net "M_B_CPU1_SB_DQ<11>")
	)
	(segment
		(start 90.494866 -233.87812)
		(end 90.494612 -233.877866)
		(width 0.20066)
		(layer "F.Cu")
		(net "M_B_CPU1_SB_DQ<11>")
	)
	(segment
		(start 44.987464 -220.69171)
		(end 44.749466 -220.69171)
		(width 0.101854)
		(layer "F.Cu")
		(net "M_B_CPU1_SB_DQ<11>")
	)
	(segment
		(start 51.064414 -220.266768)
		(end 49.959514 -220.266768)
		(width 0.20066)
		(layer "F.Cu")
		(net "M_B_CPU1_SB_DQ<11>")
	)
	(segment
		(start 90.494612 -233.877866)
		(end 90.494612 -233.34218)
		(width 0.20066)
		(layer "F.Cu")
		(net "M_B_CPU1_SB_DQ<11>")
	)
	(segment
		(start 47.753778 -220.390974)
		(end 47.753778 -220.542612)
		(width 0.20066)
		(layer "F.Cu")
		(net "M_B_CPU1_SB_DQ<11>")
	)
	(segment
		(start 47.753778 -220.542612)
		(end 47.60468 -220.69171)
		(width 0.20066)
		(layer "F.Cu")
		(net "M_B_CPU1_SB_DQ<11>")
	)
	(segment
		(start 44.38142 -220.705934)
		(end 44.238926 -220.56344)
		(width 0.20066)
		(layer "F.Cu")
		(net "M_B_CPU1_SB_DQ<11>")
	)
	(segment
		(start 48.935894 -220.474286)
		(end 48.489362 -220.474286)
		(width 0.20066)
		(layer "F.Cu")
		(net "M_B_CPU1_SB_DQ<11>")
	)
	(segment
		(start 48.489362 -220.474286)
		(end 48.277526 -220.26245)
		(width 0.20066)
		(layer "F.Cu")
		(net "M_B_CPU1_SB_DQ<11>")
	)
	(segment
		(start 47.60468 -220.69171)
		(end 47.060358 -220.69171)
		(width 0.20066)
		(layer "F.Cu")
		(net "M_B_CPU1_SB_DQ<11>")
	)
	(segment
		(start 44.238926 -220.56344)
		(end 44.238926 -220.392752)
		(width 0.20066)
		(layer "F.Cu")
		(net "M_B_CPU1_SB_DQ<11>")
	)
	(segment
		(start 44.112942 -220.266768)
		(end 42.415714 -220.266768)
		(width 0.20066)
		(layer "F.Cu")
		(net "M_B_CPU1_SB_DQ<11>")
	)
	(segment
		(start 44.749466 -220.69171)
		(end 44.735242 -220.705934)
		(width 0.101854)
		(layer "F.Cu")
		(net "M_B_CPU1_SB_DQ<11>")
	)
	(segment
		(start 47.882302 -220.26245)
		(end 47.753778 -220.390974)
		(width 0.20066)
		(layer "F.Cu")
		(net "M_B_CPU1_SB_DQ<11>")
	)
	(segment
		(start 44.238926 -220.392752)
		(end 44.112942 -220.266768)
		(width 0.20066)
		(layer "F.Cu")
		(net "M_B_CPU1_SB_DQ<11>")
	)
	(segment
		(start 85.057996 -233.657902)
		(end 85.043264 -233.666538)
		(width 0.088646)
		(layer "In2.Cu")
		(net "M_B_CPU1_SB_DQ<11>")
	)
	(segment
		(start 68.370958 -219.391992)
		(end 68.076318 -219.391992)
		(width 0.18288)
		(layer "In2.Cu")
		(net "M_B_CPU1_SB_DQ<11>")
	)
	(segment
		(start 84.010754 -233.590846)
		(end 83.449922 -233.030014)
		(width 0.088646)
		(layer "In2.Cu")
		(net "M_B_CPU1_SB_DQ<11>")
	)
	(segment
		(start 52.422298 -220.882972)
		(end 51.680618 -220.882972)
		(width 0.18288)
		(layer "In2.Cu")
		(net "M_B_CPU1_SB_DQ<11>")
	)
	(segment
		(start 87.862664 -233.666792)
		(end 87.862664 -233.666538)
		(width 0.088646)
		(layer "In2.Cu")
		(net "M_B_CPU1_SB_DQ<11>")
	)
	(segment
		(start 83.449922 -233.030014)
		(end 83.241896 -233.030014)
		(width 0.088646)
		(layer "In2.Cu")
		(net "M_B_CPU1_SB_DQ<11>")
	)
	(segment
		(start 68.589398 -219.610432)
		(end 68.370958 -219.391992)
		(width 0.18288)
		(layer "In2.Cu")
		(net "M_B_CPU1_SB_DQ<11>")
	)
	(segment
		(start 56.675274 -221.576138)
		(end 56.465216 -221.786196)
		(width 0.18288)
		(layer "In2.Cu")
		(net "M_B_CPU1_SB_DQ<11>")
	)
	(segment
		(start 58.795158 -221.76486)
		(end 58.45937 -221.76486)
		(width 0.18288)
		(layer "In2.Cu")
		(net "M_B_CPU1_SB_DQ<11>")
	)
	(segment
		(start 83.241896 -233.030014)
		(end 82.880454 -233.030014)
		(width 0.18288)
		(layer "In2.Cu")
		(net "M_B_CPU1_SB_DQ<11>")
	)
	(segment
		(start 58.45937 -221.76486)
		(end 58.270648 -221.576138)
		(width 0.18288)
		(layer "In2.Cu")
		(net "M_B_CPU1_SB_DQ<11>")
	)
	(segment
		(start 67.883278 -219.585032)
		(end 67.883278 -220.781372)
		(width 0.18288)
		(layer "In2.Cu")
		(net "M_B_CPU1_SB_DQ<11>")
	)
	(segment
		(start 60.146184 -220.705172)
		(end 59.863736 -220.98762)
		(width 0.18288)
		(layer "In2.Cu")
		(net "M_B_CPU1_SB_DQ<11>")
	)
	(segment
		(start 68.589398 -220.79204)
		(end 68.589398 -219.610432)
		(width 0.18288)
		(layer "In2.Cu")
		(net "M_B_CPU1_SB_DQ<11>")
	)
	(segment
		(start 67.370198 -220.98508)
		(end 67.177158 -220.79204)
		(width 0.18288)
		(layer "In2.Cu")
		(net "M_B_CPU1_SB_DQ<11>")
	)
	(segment
		(start 56.12257 -221.786196)
		(end 55.6387 -221.302326)
		(width 0.18288)
		(layer "In2.Cu")
		(net "M_B_CPU1_SB_DQ<11>")
	)
	(segment
		(start 69.295518 -220.781372)
		(end 69.09181 -220.98508)
		(width 0.18288)
		(layer "In2.Cu")
		(net "M_B_CPU1_SB_DQ<11>")
	)
	(segment
		(start 52.600352 -220.704918)
		(end 52.422298 -220.882972)
		(width 0.18288)
		(layer "In2.Cu")
		(net "M_B_CPU1_SB_DQ<11>")
	)
	(segment
		(start 88.124538 -233.449622)
		(end 88.056212 -233.517948)
		(width 0.088646)
		(layer "In2.Cu")
		(net "M_B_CPU1_SB_DQ<11>")
	)
	(segment
		(start 66.984118 -219.859352)
		(end 63.35014 -219.859352)
		(width 0.18288)
		(layer "In2.Cu")
		(net "M_B_CPU1_SB_DQ<11>")
	)
	(segment
		(start 55.6387 -221.302326)
		(end 55.6387 -220.783404)
		(width 0.18288)
		(layer "In2.Cu")
		(net "M_B_CPU1_SB_DQ<11>")
	)
	(segment
		(start 59.572398 -220.98762)
		(end 58.795158 -221.76486)
		(width 0.18288)
		(layer "In2.Cu")
		(net "M_B_CPU1_SB_DQ<11>")
	)
	(segment
		(start 68.076318 -219.391992)
		(end 67.883278 -219.585032)
		(width 0.18288)
		(layer "In2.Cu")
		(net "M_B_CPU1_SB_DQ<11>")
	)
	(segment
		(start 88.808306 -233.021124)
		(end 88.802464 -233.017822)
		(width 0.088646)
		(layer "In2.Cu")
		(net "M_B_CPU1_SB_DQ<11>")
	)
	(segment
		(start 56.465216 -221.786196)
		(end 56.12257 -221.786196)
		(width 0.18288)
		(layer "In2.Cu")
		(net "M_B_CPU1_SB_DQ<11>")
	)
	(segment
		(start 82.880454 -233.030014)
		(end 69.709792 -219.859352)
		(width 0.18288)
		(layer "In2.Cu")
		(net "M_B_CPU1_SB_DQ<11>")
	)
	(segment
		(start 88.340438 -233.084878)
		(end 88.229694 -233.195622)
		(width 0.088646)
		(layer "In2.Cu")
		(net "M_B_CPU1_SB_DQ<11>")
	)
	(segment
		(start 67.883278 -220.781372)
		(end 67.67957 -220.98508)
		(width 0.18288)
		(layer "In2.Cu")
		(net "M_B_CPU1_SB_DQ<11>")
	)
	(segment
		(start 69.709792 -219.859352)
		(end 69.488558 -219.859352)
		(width 0.18288)
		(layer "In2.Cu")
		(net "M_B_CPU1_SB_DQ<11>")
	)
	(segment
		(start 63.35014 -219.859352)
		(end 62.50432 -220.705172)
		(width 0.18288)
		(layer "In2.Cu")
		(net "M_B_CPU1_SB_DQ<11>")
	)
	(segment
		(start 69.488558 -219.859352)
		(end 69.295518 -220.052392)
		(width 0.18288)
		(layer "In2.Cu")
		(net "M_B_CPU1_SB_DQ<11>")
	)
	(segment
		(start 55.6387 -220.783404)
		(end 55.411878 -220.556582)
		(width 0.18288)
		(layer "In2.Cu")
		(net "M_B_CPU1_SB_DQ<11>")
	)
	(segment
		(start 67.67957 -220.98508)
		(end 67.370198 -220.98508)
		(width 0.18288)
		(layer "In2.Cu")
		(net "M_B_CPU1_SB_DQ<11>")
	)
	(segment
		(start 69.295518 -220.052392)
		(end 69.295518 -220.781372)
		(width 0.18288)
		(layer "In2.Cu")
		(net "M_B_CPU1_SB_DQ<11>")
	)
	(segment
		(start 54.4322 -220.853762)
		(end 54.283356 -220.704918)
		(width 0.18288)
		(layer "In2.Cu")
		(net "M_B_CPU1_SB_DQ<11>")
	)
	(segment
		(start 67.177158 -220.79204)
		(end 67.177158 -220.052392)
		(width 0.18288)
		(layer "In2.Cu")
		(net "M_B_CPU1_SB_DQ<11>")
	)
	(segment
		(start 62.50432 -220.705172)
		(end 60.146184 -220.705172)
		(width 0.18288)
		(layer "In2.Cu")
		(net "M_B_CPU1_SB_DQ<11>")
	)
	(segment
		(start 84.386166 -233.590846)
		(end 84.010754 -233.590846)
		(width 0.088646)
		(layer "In2.Cu")
		(net "M_B_CPU1_SB_DQ<11>")
	)
	(segment
		(start 51.680618 -220.882972)
		(end 51.064414 -220.266768)
		(width 0.18288)
		(layer "In2.Cu")
		(net "M_B_CPU1_SB_DQ<11>")
	)
	(segment
		(start 68.782438 -220.98508)
		(end 68.589398 -220.79204)
		(width 0.18288)
		(layer "In2.Cu")
		(net "M_B_CPU1_SB_DQ<11>")
	)
	(segment
		(start 59.863736 -220.98762)
		(end 59.572398 -220.98762)
		(width 0.18288)
		(layer "In2.Cu")
		(net "M_B_CPU1_SB_DQ<11>")
	)
	(segment
		(start 69.09181 -220.98508)
		(end 68.782438 -220.98508)
		(width 0.18288)
		(layer "In2.Cu")
		(net "M_B_CPU1_SB_DQ<11>")
	)
	(segment
		(start 90.140282 -233.247438)
		(end 89.736422 -233.01452)
		(width 0.088646)
		(layer "In2.Cu")
		(net "M_B_CPU1_SB_DQ<11>")
	)
	(segment
		(start 67.177158 -220.052392)
		(end 66.984118 -219.859352)
		(width 0.18288)
		(layer "In2.Cu")
		(net "M_B_CPU1_SB_DQ<11>")
	)
	(segment
		(start 55.411878 -220.556582)
		(end 55.169562 -220.556582)
		(width 0.18288)
		(layer "In2.Cu")
		(net "M_B_CPU1_SB_DQ<11>")
	)
	(segment
		(start 54.872382 -220.853762)
		(end 54.4322 -220.853762)
		(width 0.18288)
		(layer "In2.Cu")
		(net "M_B_CPU1_SB_DQ<11>")
	)
	(segment
		(start 58.270648 -221.576138)
		(end 56.675274 -221.576138)
		(width 0.18288)
		(layer "In2.Cu")
		(net "M_B_CPU1_SB_DQ<11>")
	)
	(segment
		(start 55.169562 -220.556582)
		(end 54.872382 -220.853762)
		(width 0.18288)
		(layer "In2.Cu")
		(net "M_B_CPU1_SB_DQ<11>")
	)
	(segment
		(start 88.802464 -233.017822)
		(end 88.798654 -233.015536)
		(width 0.088646)
		(layer "In2.Cu")
		(net "M_B_CPU1_SB_DQ<11>")
	)
	(segment
		(start 54.283356 -220.704918)
		(end 52.600352 -220.704918)
		(width 0.18288)
		(layer "In2.Cu")
		(net "M_B_CPU1_SB_DQ<11>")
	)
	(arc
		(start 84.668868 -233.666538)
		(mid 84.532502 -233.61006)
		(end 84.386166 -233.590846)
		(width 0.088646)
		(layer "In2.Cu")
		(net "M_B_CPU1_SB_DQ<11>")
	)
	(arc
		(start 87.862664 -233.666538)
		(mid 87.675466 -233.716681)
		(end 87.488268 -233.666538)
		(width 0.088646)
		(layer "In2.Cu")
		(net "M_B_CPU1_SB_DQ<11>")
	)
	(arc
		(start 88.169242 -233.341672)
		(mid 88.157622 -233.40009)
		(end 88.124538 -233.449622)
		(width 0.088646)
		(layer "In2.Cu")
		(net "M_B_CPU1_SB_DQ<11>")
	)
	(arc
		(start 86.922864 -233.666538)
		(mid 86.735666 -233.716681)
		(end 86.548468 -233.666538)
		(width 0.088646)
		(layer "In2.Cu")
		(net "M_B_CPU1_SB_DQ<11>")
	)
	(arc
		(start 88.056212 -233.517948)
		(mid 87.964293 -233.598684)
		(end 87.862664 -233.666792)
		(width 0.088646)
		(layer "In2.Cu")
		(net "M_B_CPU1_SB_DQ<11>")
	)
	(arc
		(start 90.494612 -233.34218)
		(mid 90.311219 -233.318093)
		(end 90.140282 -233.247438)
		(width 0.088646)
		(layer "In2.Cu")
		(net "M_B_CPU1_SB_DQ<11>")
	)
	(arc
		(start 89.736422 -233.01452)
		(mid 89.551567 -232.96757)
		(end 89.367614 -233.017822)
		(width 0.088646)
		(layer "In2.Cu")
		(net "M_B_CPU1_SB_DQ<11>")
	)
	(arc
		(start 88.229694 -233.195622)
		(mid 88.184974 -233.262645)
		(end 88.169242 -233.341672)
		(width 0.088646)
		(layer "In2.Cu")
		(net "M_B_CPU1_SB_DQ<11>")
	)
	(arc
		(start 85.043264 -233.666538)
		(mid 84.856066 -233.716681)
		(end 84.668868 -233.666538)
		(width 0.088646)
		(layer "In2.Cu")
		(net "M_B_CPU1_SB_DQ<11>")
	)
	(arc
		(start 85.983064 -233.666538)
		(mid 85.795866 -233.716681)
		(end 85.608668 -233.666538)
		(width 0.088646)
		(layer "In2.Cu")
		(net "M_B_CPU1_SB_DQ<11>")
	)
	(arc
		(start 86.548468 -233.666538)
		(mid 86.265766 -233.590796)
		(end 85.983064 -233.666538)
		(width 0.088646)
		(layer "In2.Cu")
		(net "M_B_CPU1_SB_DQ<11>")
	)
	(arc
		(start 85.608668 -233.666538)
		(mid 85.334439 -233.590613)
		(end 85.057996 -233.657902)
		(width 0.088646)
		(layer "In2.Cu")
		(net "M_B_CPU1_SB_DQ<11>")
	)
	(arc
		(start 88.427814 -233.017822)
		(mid 88.381923 -233.04848)
		(end 88.340438 -233.084878)
		(width 0.088646)
		(layer "In2.Cu")
		(net "M_B_CPU1_SB_DQ<11>")
	)
	(arc
		(start 88.798654 -233.015536)
		(mid 88.612935 -232.967584)
		(end 88.427814 -233.017822)
		(width 0.088646)
		(layer "In2.Cu")
		(net "M_B_CPU1_SB_DQ<11>")
	)
	(arc
		(start 87.488268 -233.666538)
		(mid 87.205566 -233.590796)
		(end 86.922864 -233.666538)
		(width 0.088646)
		(layer "In2.Cu")
		(net "M_B_CPU1_SB_DQ<11>")
	)
	(arc
		(start 89.367614 -233.017822)
		(mid 89.088411 -233.093462)
		(end 88.808306 -233.021124)
		(width 0.088646)
		(layer "In2.Cu")
		(net "M_B_CPU1_SB_DQ<11>")
	)
	(segment
		(start 90.024712 -234.69219)
		(end 90.024966 -234.691936)
		(width 0.20066)
		(layer "F.Cu")
		(net "M_B_CPU1_SB_DQ<10>")
	)
	(segment
		(start 49.959514 -221.96679)
		(end 48.64481 -221.96679)
		(width 0.20066)
		(layer "F.Cu")
		(net "M_B_CPU1_SB_DQ<10>")
	)
	(segment
		(start 43.99788 -221.531688)
		(end 43.562778 -221.96679)
		(width 0.20066)
		(layer "F.Cu")
		(net "M_B_CPU1_SB_DQ<10>")
	)
	(segment
		(start 90.024966 -234.691936)
		(end 90.024966 -234.15625)
		(width 0.20066)
		(layer "F.Cu")
		(net "M_B_CPU1_SB_DQ<10>")
	)
	(segment
		(start 47.693326 -221.541848)
		(end 47.060358 -221.541848)
		(width 0.20066)
		(layer "F.Cu")
		(net "M_B_CPU1_SB_DQ<10>")
	)
	(segment
		(start 51.064414 -221.96679)
		(end 49.959514 -221.96679)
		(width 0.20066)
		(layer "F.Cu")
		(net "M_B_CPU1_SB_DQ<10>")
	)
	(segment
		(start 48.004476 -222.178626)
		(end 47.83709 -222.01124)
		(width 0.20066)
		(layer "F.Cu")
		(net "M_B_CPU1_SB_DQ<10>")
	)
	(segment
		(start 48.432974 -222.178626)
		(end 48.004476 -222.178626)
		(width 0.20066)
		(layer "F.Cu")
		(net "M_B_CPU1_SB_DQ<10>")
	)
	(segment
		(start 44.745402 -221.541848)
		(end 44.735242 -221.531688)
		(width 0.101854)
		(layer "F.Cu")
		(net "M_B_CPU1_SB_DQ<10>")
	)
	(segment
		(start 47.83709 -221.685612)
		(end 47.693326 -221.541848)
		(width 0.20066)
		(layer "F.Cu")
		(net "M_B_CPU1_SB_DQ<10>")
	)
	(segment
		(start 47.060358 -221.541848)
		(end 45.000418 -221.541848)
		(width 0.1016)
		(layer "F.Cu")
		(net "M_B_CPU1_SB_DQ<10>")
	)
	(segment
		(start 47.83709 -222.01124)
		(end 47.83709 -221.685612)
		(width 0.20066)
		(layer "F.Cu")
		(net "M_B_CPU1_SB_DQ<10>")
	)
	(segment
		(start 44.735242 -221.531688)
		(end 43.99788 -221.531688)
		(width 0.20066)
		(layer "F.Cu")
		(net "M_B_CPU1_SB_DQ<10>")
	)
	(segment
		(start 43.562778 -221.96679)
		(end 42.415714 -221.96679)
		(width 0.20066)
		(layer "F.Cu")
		(net "M_B_CPU1_SB_DQ<10>")
	)
	(segment
		(start 48.64481 -221.96679)
		(end 48.432974 -222.178626)
		(width 0.20066)
		(layer "F.Cu")
		(net "M_B_CPU1_SB_DQ<10>")
	)
	(segment
		(start 45.000418 -221.541848)
		(end 44.745402 -221.541848)
		(width 0.101854)
		(layer "F.Cu")
		(net "M_B_CPU1_SB_DQ<10>")
	)
	(segment
		(start 63.074804 -222.975932)
		(end 62.8015 -222.975932)
		(width 0.18288)
		(layer "In2.Cu")
		(net "M_B_CPU1_SB_DQ<10>")
	)
	(segment
		(start 52.84216 -222.08744)
		(end 52.25034 -222.67926)
		(width 0.18288)
		(layer "In2.Cu")
		(net "M_B_CPU1_SB_DQ<10>")
	)
	(segment
		(start 63.403988 -222.373444)
		(end 63.403988 -222.646748)
		(width 0.18288)
		(layer "In2.Cu")
		(net "M_B_CPU1_SB_DQ<10>")
	)
	(segment
		(start 65.59296 -221.209108)
		(end 64.492886 -221.209108)
		(width 0.18288)
		(layer "In2.Cu")
		(net "M_B_CPU1_SB_DQ<10>")
	)
	(segment
		(start 83.88858 -234.404662)
		(end 83.530694 -234.046776)
		(width 0.088646)
		(layer "In2.Cu")
		(net "M_B_CPU1_SB_DQ<10>")
	)
	(segment
		(start 83.241896 -234.046776)
		(end 82.43062 -234.046776)
		(width 0.18288)
		(layer "In2.Cu")
		(net "M_B_CPU1_SB_DQ<10>")
	)
	(segment
		(start 63.043054 -221.739206)
		(end 63.043054 -222.01251)
		(width 0.18288)
		(layer "In2.Cu")
		(net "M_B_CPU1_SB_DQ<10>")
	)
	(segment
		(start 58.53176 -223.46285)
		(end 57.989216 -222.920306)
		(width 0.18288)
		(layer "In2.Cu")
		(net "M_B_CPU1_SB_DQ<10>")
	)
	(segment
		(start 55.42407 -222.555308)
		(end 55.124858 -222.256096)
		(width 0.18288)
		(layer "In2.Cu")
		(net "M_B_CPU1_SB_DQ<10>")
	)
	(segment
		(start 85.527896 -234.471972)
		(end 85.513164 -234.480608)
		(width 0.088646)
		(layer "In2.Cu")
		(net "M_B_CPU1_SB_DQ<10>")
	)
	(segment
		(start 64.155828 -221.546166)
		(end 63.236094 -221.546166)
		(width 0.18288)
		(layer "In2.Cu")
		(net "M_B_CPU1_SB_DQ<10>")
	)
	(segment
		(start 70.437502 -222.053658)
		(end 66.82994 -222.053658)
		(width 0.18288)
		(layer "In2.Cu")
		(net "M_B_CPU1_SB_DQ<10>")
	)
	(segment
		(start 56.134508 -224.16008)
		(end 55.390288 -224.16008)
		(width 0.18288)
		(layer "In2.Cu")
		(net "M_B_CPU1_SB_DQ<10>")
	)
	(segment
		(start 63.236094 -221.546166)
		(end 63.043054 -221.739206)
		(width 0.18288)
		(layer "In2.Cu")
		(net "M_B_CPU1_SB_DQ<10>")
	)
	(segment
		(start 66.322448 -221.546166)
		(end 65.930018 -221.546166)
		(width 0.18288)
		(layer "In2.Cu")
		(net "M_B_CPU1_SB_DQ<10>")
	)
	(segment
		(start 55.42407 -222.95231)
		(end 55.42407 -222.555308)
		(width 0.18288)
		(layer "In2.Cu")
		(net "M_B_CPU1_SB_DQ<10>")
	)
	(segment
		(start 61.946282 -222.478092)
		(end 61.514228 -222.046038)
		(width 0.18288)
		(layer "In2.Cu")
		(net "M_B_CPU1_SB_DQ<10>")
	)
	(segment
		(start 53.926994 -222.08744)
		(end 52.84216 -222.08744)
		(width 0.18288)
		(layer "In2.Cu")
		(net "M_B_CPU1_SB_DQ<10>")
	)
	(segment
		(start 86.467696 -234.471972)
		(end 86.452964 -234.480608)
		(width 0.088646)
		(layer "In2.Cu")
		(net "M_B_CPU1_SB_DQ<10>")
	)
	(segment
		(start 57.00649 -222.920306)
		(end 56.454802 -223.471994)
		(width 0.18288)
		(layer "In2.Cu")
		(net "M_B_CPU1_SB_DQ<10>")
	)
	(segment
		(start 65.930018 -221.546166)
		(end 65.59296 -221.209108)
		(width 0.18288)
		(layer "In2.Cu")
		(net "M_B_CPU1_SB_DQ<10>")
	)
	(segment
		(start 62.8015 -222.975932)
		(end 62.30366 -222.478092)
		(width 0.18288)
		(layer "In2.Cu")
		(net "M_B_CPU1_SB_DQ<10>")
	)
	(segment
		(start 63.043054 -222.01251)
		(end 63.403988 -222.373444)
		(width 0.18288)
		(layer "In2.Cu")
		(net "M_B_CPU1_SB_DQ<10>")
	)
	(segment
		(start 83.530694 -234.046776)
		(end 83.241896 -234.046776)
		(width 0.088646)
		(layer "In2.Cu")
		(net "M_B_CPU1_SB_DQ<10>")
	)
	(segment
		(start 82.43062 -234.046776)
		(end 70.437502 -222.053658)
		(width 0.18288)
		(layer "In2.Cu")
		(net "M_B_CPU1_SB_DQ<10>")
	)
	(segment
		(start 55.124858 -222.256096)
		(end 54.851554 -222.256096)
		(width 0.18288)
		(layer "In2.Cu")
		(net "M_B_CPU1_SB_DQ<10>")
	)
	(segment
		(start 87.407496 -234.471972)
		(end 87.392764 -234.480608)
		(width 0.088646)
		(layer "In2.Cu")
		(net "M_B_CPU1_SB_DQ<10>")
	)
	(segment
		(start 54.939692 -223.436688)
		(end 55.42407 -222.95231)
		(width 0.18288)
		(layer "In2.Cu")
		(net "M_B_CPU1_SB_DQ<10>")
	)
	(segment
		(start 61.514228 -222.046038)
		(end 60.559188 -222.046038)
		(width 0.18288)
		(layer "In2.Cu")
		(net "M_B_CPU1_SB_DQ<10>")
	)
	(segment
		(start 55.390288 -224.16008)
		(end 54.939692 -223.709484)
		(width 0.18288)
		(layer "In2.Cu")
		(net "M_B_CPU1_SB_DQ<10>")
	)
	(segment
		(start 88.520016 -234.148884)
		(end 88.520016 -234.161076)
		(width 0.088646)
		(layer "In2.Cu")
		(net "M_B_CPU1_SB_DQ<10>")
	)
	(segment
		(start 56.454802 -223.839786)
		(end 56.134508 -224.16008)
		(width 0.18288)
		(layer "In2.Cu")
		(net "M_B_CPU1_SB_DQ<10>")
	)
	(segment
		(start 62.30366 -222.478092)
		(end 61.946282 -222.478092)
		(width 0.18288)
		(layer "In2.Cu")
		(net "M_B_CPU1_SB_DQ<10>")
	)
	(segment
		(start 54.851554 -222.256096)
		(end 54.61 -222.49765)
		(width 0.18288)
		(layer "In2.Cu")
		(net "M_B_CPU1_SB_DQ<10>")
	)
	(segment
		(start 56.454802 -223.471994)
		(end 56.454802 -223.839786)
		(width 0.18288)
		(layer "In2.Cu")
		(net "M_B_CPU1_SB_DQ<10>")
	)
	(segment
		(start 88.695784 -233.872532)
		(end 88.591136 -233.976926)
		(width 0.088646)
		(layer "In2.Cu")
		(net "M_B_CPU1_SB_DQ<10>")
	)
	(segment
		(start 83.916012 -234.404662)
		(end 83.88858 -234.404662)
		(width 0.088646)
		(layer "In2.Cu")
		(net "M_B_CPU1_SB_DQ<10>")
	)
	(segment
		(start 59.142376 -223.46285)
		(end 58.53176 -223.46285)
		(width 0.18288)
		(layer "In2.Cu")
		(net "M_B_CPU1_SB_DQ<10>")
	)
	(segment
		(start 59.30519 -222.874332)
		(end 59.30519 -223.300036)
		(width 0.18288)
		(layer "In2.Cu")
		(net "M_B_CPU1_SB_DQ<10>")
	)
	(segment
		(start 63.403988 -222.646748)
		(end 63.074804 -222.975932)
		(width 0.18288)
		(layer "In2.Cu")
		(net "M_B_CPU1_SB_DQ<10>")
	)
	(segment
		(start 60.559188 -222.046038)
		(end 59.97067 -222.634556)
		(width 0.18288)
		(layer "In2.Cu")
		(net "M_B_CPU1_SB_DQ<10>")
	)
	(segment
		(start 90.024966 -234.15625)
		(end 89.638886 -233.841798)
		(width 0.088646)
		(layer "In2.Cu")
		(net "M_B_CPU1_SB_DQ<10>")
	)
	(segment
		(start 66.82994 -222.053658)
		(end 66.322448 -221.546166)
		(width 0.18288)
		(layer "In2.Cu")
		(net "M_B_CPU1_SB_DQ<10>")
	)
	(segment
		(start 59.30519 -223.300036)
		(end 59.142376 -223.46285)
		(width 0.18288)
		(layer "In2.Cu")
		(net "M_B_CPU1_SB_DQ<10>")
	)
	(segment
		(start 54.61 -222.49765)
		(end 54.337204 -222.49765)
		(width 0.18288)
		(layer "In2.Cu")
		(net "M_B_CPU1_SB_DQ<10>")
	)
	(segment
		(start 59.97067 -222.634556)
		(end 59.544966 -222.634556)
		(width 0.18288)
		(layer "In2.Cu")
		(net "M_B_CPU1_SB_DQ<10>")
	)
	(segment
		(start 57.989216 -222.920306)
		(end 57.00649 -222.920306)
		(width 0.18288)
		(layer "In2.Cu")
		(net "M_B_CPU1_SB_DQ<10>")
	)
	(segment
		(start 52.25034 -222.67926)
		(end 51.776884 -222.67926)
		(width 0.18288)
		(layer "In2.Cu")
		(net "M_B_CPU1_SB_DQ<10>")
	)
	(segment
		(start 54.939692 -223.709484)
		(end 54.939692 -223.436688)
		(width 0.18288)
		(layer "In2.Cu")
		(net "M_B_CPU1_SB_DQ<10>")
	)
	(segment
		(start 84.588096 -234.471972)
		(end 84.573364 -234.480608)
		(width 0.088646)
		(layer "In2.Cu")
		(net "M_B_CPU1_SB_DQ<10>")
	)
	(segment
		(start 51.776884 -222.67926)
		(end 51.064414 -221.96679)
		(width 0.18288)
		(layer "In2.Cu")
		(net "M_B_CPU1_SB_DQ<10>")
	)
	(segment
		(start 59.544966 -222.634556)
		(end 59.30519 -222.874332)
		(width 0.18288)
		(layer "In2.Cu")
		(net "M_B_CPU1_SB_DQ<10>")
	)
	(segment
		(start 54.337204 -222.49765)
		(end 53.926994 -222.08744)
		(width 0.18288)
		(layer "In2.Cu")
		(net "M_B_CPU1_SB_DQ<10>")
	)
	(segment
		(start 64.492886 -221.209108)
		(end 64.155828 -221.546166)
		(width 0.18288)
		(layer "In2.Cu")
		(net "M_B_CPU1_SB_DQ<10>")
	)
	(arc
		(start 89.638886 -233.841798)
		(mid 89.375796 -233.740805)
		(end 89.096088 -233.706416)
		(width 0.088646)
		(layer "In2.Cu")
		(net "M_B_CPU1_SB_DQ<10>")
	)
	(arc
		(start 86.078568 -234.480608)
		(mid 85.804369 -234.404773)
		(end 85.527896 -234.471972)
		(width 0.088646)
		(layer "In2.Cu")
		(net "M_B_CPU1_SB_DQ<10>")
	)
	(arc
		(start 88.520016 -234.161076)
		(mid 88.468527 -234.345615)
		(end 88.332564 -234.480608)
		(width 0.088646)
		(layer "In2.Cu")
		(net "M_B_CPU1_SB_DQ<10>")
	)
	(arc
		(start 86.452964 -234.480608)
		(mid 86.265766 -234.530751)
		(end 86.078568 -234.480608)
		(width 0.088646)
		(layer "In2.Cu")
		(net "M_B_CPU1_SB_DQ<10>")
	)
	(arc
		(start 87.958168 -234.480608)
		(mid 87.683969 -234.404773)
		(end 87.407496 -234.471972)
		(width 0.088646)
		(layer "In2.Cu")
		(net "M_B_CPU1_SB_DQ<10>")
	)
	(arc
		(start 87.018368 -234.480608)
		(mid 86.744169 -234.404773)
		(end 86.467696 -234.471972)
		(width 0.088646)
		(layer "In2.Cu")
		(net "M_B_CPU1_SB_DQ<10>")
	)
	(arc
		(start 85.138768 -234.480608)
		(mid 84.864569 -234.404773)
		(end 84.588096 -234.471972)
		(width 0.088646)
		(layer "In2.Cu")
		(net "M_B_CPU1_SB_DQ<10>")
	)
	(arc
		(start 85.513164 -234.480608)
		(mid 85.325966 -234.530751)
		(end 85.138768 -234.480608)
		(width 0.088646)
		(layer "In2.Cu")
		(net "M_B_CPU1_SB_DQ<10>")
	)
	(arc
		(start 88.591136 -233.976926)
		(mid 88.53842 -234.055821)
		(end 88.520016 -234.148884)
		(width 0.088646)
		(layer "In2.Cu")
		(net "M_B_CPU1_SB_DQ<10>")
	)
	(arc
		(start 84.198968 -234.480608)
		(mid 84.062496 -234.423985)
		(end 83.916012 -234.404662)
		(width 0.088646)
		(layer "In2.Cu")
		(net "M_B_CPU1_SB_DQ<10>")
	)
	(arc
		(start 87.392764 -234.480608)
		(mid 87.205566 -234.530751)
		(end 87.018368 -234.480608)
		(width 0.088646)
		(layer "In2.Cu")
		(net "M_B_CPU1_SB_DQ<10>")
	)
	(arc
		(start 84.573364 -234.480608)
		(mid 84.386166 -234.530751)
		(end 84.198968 -234.480608)
		(width 0.088646)
		(layer "In2.Cu")
		(net "M_B_CPU1_SB_DQ<10>")
	)
	(arc
		(start 89.096088 -233.706416)
		(mid 88.881078 -233.753674)
		(end 88.695784 -233.872532)
		(width 0.088646)
		(layer "In2.Cu")
		(net "M_B_CPU1_SB_DQ<10>")
	)
	(arc
		(start 88.332564 -234.480608)
		(mid 88.145366 -234.530751)
		(end 87.958168 -234.480608)
		(width 0.088646)
		(layer "In2.Cu")
		(net "M_B_CPU1_SB_DQ<10>")
	)
	(segment
		(start 41.29151 -231.733598)
		(end 40.729662 -231.733598)
		(width 0.20066)
		(layer "F.Cu")
		(net "M_B_CPU1_SB_DQ<0>")
	)
	(segment
		(start 43.616626 -231.741726)
		(end 41.547542 -231.741726)
		(width 0.1016)
		(layer "F.Cu")
		(net "M_B_CPU1_SB_DQ<0>")
	)
	(segment
		(start 44.490386 -232.166668)
		(end 44.065444 -231.741726)
		(width 0.20066)
		(layer "F.Cu")
		(net "M_B_CPU1_SB_DQ<0>")
	)
	(segment
		(start 44.065444 -231.741726)
		(end 43.616626 -231.741726)
		(width 0.20066)
		(layer "F.Cu")
		(net "M_B_CPU1_SB_DQ<0>")
	)
	(segment
		(start 40.520112 -231.943148)
		(end 40.520112 -232.232708)
		(width 0.20066)
		(layer "F.Cu")
		(net "M_B_CPU1_SB_DQ<0>")
	)
	(segment
		(start 45.859446 -232.166668)
		(end 44.490386 -232.166668)
		(width 0.20066)
		(layer "F.Cu")
		(net "M_B_CPU1_SB_DQ<0>")
	)
	(segment
		(start 41.547542 -231.741726)
		(end 41.299638 -231.741726)
		(width 0.101854)
		(layer "F.Cu")
		(net "M_B_CPU1_SB_DQ<0>")
	)
	(segment
		(start 40.347392 -232.405428)
		(end 39.888668 -232.405428)
		(width 0.20066)
		(layer "F.Cu")
		(net "M_B_CPU1_SB_DQ<0>")
	)
	(segment
		(start 39.888668 -232.405428)
		(end 39.649908 -232.166668)
		(width 0.20066)
		(layer "F.Cu")
		(net "M_B_CPU1_SB_DQ<0>")
	)
	(segment
		(start 92.374212 -237.133638)
		(end 92.374212 -236.597952)
		(width 0.20066)
		(layer "F.Cu")
		(net "M_B_CPU1_SB_DQ<0>")
	)
	(segment
		(start 92.374466 -237.133892)
		(end 92.374212 -237.133638)
		(width 0.20066)
		(layer "F.Cu")
		(net "M_B_CPU1_SB_DQ<0>")
	)
	(segment
		(start 46.964346 -232.166668)
		(end 45.859446 -232.166668)
		(width 0.20066)
		(layer "F.Cu")
		(net "M_B_CPU1_SB_DQ<0>")
	)
	(segment
		(start 41.299638 -231.741726)
		(end 41.29151 -231.733598)
		(width 0.101854)
		(layer "F.Cu")
		(net "M_B_CPU1_SB_DQ<0>")
	)
	(segment
		(start 40.520112 -232.232708)
		(end 40.347392 -232.405428)
		(width 0.20066)
		(layer "F.Cu")
		(net "M_B_CPU1_SB_DQ<0>")
	)
	(segment
		(start 40.729662 -231.733598)
		(end 40.520112 -231.943148)
		(width 0.20066)
		(layer "F.Cu")
		(net "M_B_CPU1_SB_DQ<0>")
	)
	(segment
		(start 39.649908 -232.166668)
		(end 38.315646 -232.166668)
		(width 0.20066)
		(layer "F.Cu")
		(net "M_B_CPU1_SB_DQ<0>")
	)
	(segment
		(start 47.500032 -231.62895)
		(end 47.501048 -231.629966)
		(width 0.18288)
		(layer "In4.Cu")
		(net "M_B_CPU1_SB_DQ<0>")
	)
	(segment
		(start 47.500032 -231.095042)
		(end 47.500032 -231.62895)
		(width 0.18288)
		(layer "In4.Cu")
		(net "M_B_CPU1_SB_DQ<0>")
	)
	(segment
		(start 85.057996 -236.913674)
		(end 85.043264 -236.92231)
		(width 0.088646)
		(layer "In4.Cu")
		(net "M_B_CPU1_SB_DQ<0>")
	)
	(segment
		(start 47.703232 -230.891842)
		(end 47.500032 -231.095042)
		(width 0.18288)
		(layer "In4.Cu")
		(net "M_B_CPU1_SB_DQ<0>")
	)
	(segment
		(start 48.689006 -231.603042)
		(end 48.528986 -231.443022)
		(width 0.18288)
		(layer "In4.Cu")
		(net "M_B_CPU1_SB_DQ<0>")
	)
	(segment
		(start 91.627706 -236.918754)
		(end 91.621864 -236.92231)
		(width 0.088646)
		(layer "In4.Cu")
		(net "M_B_CPU1_SB_DQ<0>")
	)
	(segment
		(start 49.224692 -231.406192)
		(end 49.027842 -231.603042)
		(width 0.18288)
		(layer "In4.Cu")
		(net "M_B_CPU1_SB_DQ<0>")
	)
	(segment
		(start 58.985404 -230.213408)
		(end 58.697114 -229.925118)
		(width 0.18288)
		(layer "In4.Cu")
		(net "M_B_CPU1_SB_DQ<0>")
	)
	(segment
		(start 61.384942 -230.891842)
		(end 60.706508 -230.213408)
		(width 0.18288)
		(layer "In4.Cu")
		(net "M_B_CPU1_SB_DQ<0>")
	)
	(segment
		(start 89.367614 -236.922056)
		(end 89.3572 -236.91596)
		(width 0.088646)
		(layer "In4.Cu")
		(net "M_B_CPU1_SB_DQ<0>")
	)
	(segment
		(start 91.247214 -236.922056)
		(end 91.232482 -236.91342)
		(width 0.088646)
		(layer "In4.Cu")
		(net "M_B_CPU1_SB_DQ<0>")
	)
	(segment
		(start 62.693804 -230.891842)
		(end 61.384942 -230.891842)
		(width 0.18288)
		(layer "In4.Cu")
		(net "M_B_CPU1_SB_DQ<0>")
	)
	(segment
		(start 49.384712 -230.891842)
		(end 49.224692 -231.051862)
		(width 0.18288)
		(layer "In4.Cu")
		(net "M_B_CPU1_SB_DQ<0>")
	)
	(segment
		(start 73.226422 -237.03407)
		(end 67.933824 -231.741472)
		(width 0.18288)
		(layer "In4.Cu")
		(net "M_B_CPU1_SB_DQ<0>")
	)
	(segment
		(start 86.937596 -236.913674)
		(end 86.922864 -236.92231)
		(width 0.088646)
		(layer "In4.Cu")
		(net "M_B_CPU1_SB_DQ<0>")
	)
	(segment
		(start 53.24221 -230.32085)
		(end 53.095906 -230.467154)
		(width 0.18288)
		(layer "In4.Cu")
		(net "M_B_CPU1_SB_DQ<0>")
	)
	(segment
		(start 56.58612 -231.012746)
		(end 55.923434 -231.012746)
		(width 0.18288)
		(layer "In4.Cu")
		(net "M_B_CPU1_SB_DQ<0>")
	)
	(segment
		(start 84.582 -237.731046)
		(end 84.57311 -237.736126)
		(width 0.088646)
		(layer "In4.Cu")
		(net "M_B_CPU1_SB_DQ<0>")
	)
	(segment
		(start 64.11468 -230.891842)
		(end 63.589662 -230.891842)
		(width 0.18288)
		(layer "In4.Cu")
		(net "M_B_CPU1_SB_DQ<0>")
	)
	(segment
		(start 48.528986 -231.051862)
		(end 48.368966 -230.891842)
		(width 0.18288)
		(layer "In4.Cu")
		(net "M_B_CPU1_SB_DQ<0>")
	)
	(segment
		(start 49.224692 -231.051862)
		(end 49.224692 -231.406192)
		(width 0.18288)
		(layer "In4.Cu")
		(net "M_B_CPU1_SB_DQ<0>")
	)
	(segment
		(start 91.247214 -236.92231)
		(end 91.247214 -236.922056)
		(width 0.088646)
		(layer "In4.Cu")
		(net "M_B_CPU1_SB_DQ<0>")
	)
	(segment
		(start 83.235292 -237.03407)
		(end 83.064096 -237.03407)
		(width 0.088646)
		(layer "In4.Cu")
		(net "M_B_CPU1_SB_DQ<0>")
	)
	(segment
		(start 49.027842 -231.603042)
		(end 48.689006 -231.603042)
		(width 0.18288)
		(layer "In4.Cu")
		(net "M_B_CPU1_SB_DQ<0>")
	)
	(segment
		(start 51.732688 -230.467154)
		(end 51.308 -230.891842)
		(width 0.18288)
		(layer "In4.Cu")
		(net "M_B_CPU1_SB_DQ<0>")
	)
	(segment
		(start 85.043264 -236.92231)
		(end 85.037168 -236.925866)
		(width 0.088646)
		(layer "In4.Cu")
		(net "M_B_CPU1_SB_DQ<0>")
	)
	(segment
		(start 63.418212 -231.063292)
		(end 62.865254 -231.063292)
		(width 0.18288)
		(layer "In4.Cu")
		(net "M_B_CPU1_SB_DQ<0>")
	)
	(segment
		(start 53.095906 -230.467154)
		(end 51.732688 -230.467154)
		(width 0.18288)
		(layer "In4.Cu")
		(net "M_B_CPU1_SB_DQ<0>")
	)
	(segment
		(start 51.308 -230.891842)
		(end 49.384712 -230.891842)
		(width 0.18288)
		(layer "In4.Cu")
		(net "M_B_CPU1_SB_DQ<0>")
	)
	(segment
		(start 91.621864 -236.92231)
		(end 91.616022 -236.925612)
		(width 0.088646)
		(layer "In4.Cu")
		(net "M_B_CPU1_SB_DQ<0>")
	)
	(segment
		(start 87.862664 -236.922056)
		(end 87.851742 -236.928406)
		(width 0.088646)
		(layer "In4.Cu")
		(net "M_B_CPU1_SB_DQ<0>")
	)
	(segment
		(start 58.697114 -229.925118)
		(end 57.673748 -229.925118)
		(width 0.18288)
		(layer "In4.Cu")
		(net "M_B_CPU1_SB_DQ<0>")
	)
	(segment
		(start 62.865254 -231.063292)
		(end 62.693804 -230.891842)
		(width 0.18288)
		(layer "In4.Cu")
		(net "M_B_CPU1_SB_DQ<0>")
	)
	(segment
		(start 57.673748 -229.925118)
		(end 56.58612 -231.012746)
		(width 0.18288)
		(layer "In4.Cu")
		(net "M_B_CPU1_SB_DQ<0>")
	)
	(segment
		(start 67.933824 -231.741472)
		(end 64.964564 -231.741472)
		(width 0.18288)
		(layer "In4.Cu")
		(net "M_B_CPU1_SB_DQ<0>")
	)
	(segment
		(start 83.861656 -237.660434)
		(end 83.235292 -237.03407)
		(width 0.088646)
		(layer "In4.Cu")
		(net "M_B_CPU1_SB_DQ<0>")
	)
	(segment
		(start 92.374212 -236.597952)
		(end 92.04071 -236.783626)
		(width 0.088646)
		(layer "In4.Cu")
		(net "M_B_CPU1_SB_DQ<0>")
	)
	(segment
		(start 60.706508 -230.213408)
		(end 58.985404 -230.213408)
		(width 0.18288)
		(layer "In4.Cu")
		(net "M_B_CPU1_SB_DQ<0>")
	)
	(segment
		(start 48.368966 -230.891842)
		(end 47.703232 -230.891842)
		(width 0.18288)
		(layer "In4.Cu")
		(net "M_B_CPU1_SB_DQ<0>")
	)
	(segment
		(start 90.307414 -236.922056)
		(end 90.292682 -236.91342)
		(width 0.088646)
		(layer "In4.Cu")
		(net "M_B_CPU1_SB_DQ<0>")
	)
	(segment
		(start 63.589662 -230.891842)
		(end 63.418212 -231.063292)
		(width 0.18288)
		(layer "In4.Cu")
		(net "M_B_CPU1_SB_DQ<0>")
	)
	(segment
		(start 83.064096 -237.03407)
		(end 73.226422 -237.03407)
		(width 0.18288)
		(layer "In4.Cu")
		(net "M_B_CPU1_SB_DQ<0>")
	)
	(segment
		(start 55.231538 -230.32085)
		(end 53.24221 -230.32085)
		(width 0.18288)
		(layer "In4.Cu")
		(net "M_B_CPU1_SB_DQ<0>")
	)
	(segment
		(start 47.501048 -231.629966)
		(end 46.964346 -232.166668)
		(width 0.18288)
		(layer "In4.Cu")
		(net "M_B_CPU1_SB_DQ<0>")
	)
	(segment
		(start 55.923434 -231.012746)
		(end 55.231538 -230.32085)
		(width 0.18288)
		(layer "In4.Cu")
		(net "M_B_CPU1_SB_DQ<0>")
	)
	(segment
		(start 48.528986 -231.443022)
		(end 48.528986 -231.051862)
		(width 0.18288)
		(layer "In4.Cu")
		(net "M_B_CPU1_SB_DQ<0>")
	)
	(segment
		(start 83.91652 -237.660434)
		(end 83.861656 -237.660434)
		(width 0.088646)
		(layer "In4.Cu")
		(net "M_B_CPU1_SB_DQ<0>")
	)
	(segment
		(start 64.964564 -231.741472)
		(end 64.11468 -230.891842)
		(width 0.18288)
		(layer "In4.Cu")
		(net "M_B_CPU1_SB_DQ<0>")
	)
	(arc
		(start 91.83497 -236.850682)
		(mid 91.728019 -236.874614)
		(end 91.627706 -236.918754)
		(width 0.088646)
		(layer "In4.Cu")
		(net "M_B_CPU1_SB_DQ<0>")
	)
	(arc
		(start 85.037168 -236.925866)
		(mid 84.834581 -237.132217)
		(end 84.760562 -237.411768)
		(width 0.088646)
		(layer "In4.Cu")
		(net "M_B_CPU1_SB_DQ<0>")
	)
	(arc
		(start 86.548468 -236.92231)
		(mid 86.265766 -236.846534)
		(end 85.983064 -236.92231)
		(width 0.088646)
		(layer "In4.Cu")
		(net "M_B_CPU1_SB_DQ<0>")
	)
	(arc
		(start 88.428068 -236.922056)
		(mid 88.145366 -236.84628)
		(end 87.862664 -236.922056)
		(width 0.088646)
		(layer "In4.Cu")
		(net "M_B_CPU1_SB_DQ<0>")
	)
	(arc
		(start 85.983064 -236.92231)
		(mid 85.795866 -236.972453)
		(end 85.608668 -236.92231)
		(width 0.088646)
		(layer "In4.Cu")
		(net "M_B_CPU1_SB_DQ<0>")
	)
	(arc
		(start 91.616022 -236.925612)
		(mid 91.431167 -236.972562)
		(end 91.247214 -236.92231)
		(width 0.088646)
		(layer "In4.Cu")
		(net "M_B_CPU1_SB_DQ<0>")
	)
	(arc
		(start 92.04071 -236.783626)
		(mid 91.941079 -236.827092)
		(end 91.83497 -236.850682)
		(width 0.088646)
		(layer "In4.Cu")
		(net "M_B_CPU1_SB_DQ<0>")
	)
	(arc
		(start 86.922864 -236.92231)
		(mid 86.735666 -236.972453)
		(end 86.548468 -236.92231)
		(width 0.088646)
		(layer "In4.Cu")
		(net "M_B_CPU1_SB_DQ<0>")
	)
	(arc
		(start 84.760562 -237.411768)
		(mid 84.712883 -237.594668)
		(end 84.582 -237.731046)
		(width 0.088646)
		(layer "In4.Cu")
		(net "M_B_CPU1_SB_DQ<0>")
	)
	(arc
		(start 90.292682 -236.91342)
		(mid 90.016207 -236.8461)
		(end 89.74201 -236.922056)
		(width 0.088646)
		(layer "In4.Cu")
		(net "M_B_CPU1_SB_DQ<0>")
	)
	(arc
		(start 84.198714 -237.736126)
		(mid 84.080083 -237.684606)
		(end 83.952842 -237.66145)
		(width 0.088646)
		(layer "In4.Cu")
		(net "M_B_CPU1_SB_DQ<0>")
	)
	(arc
		(start 87.488268 -236.92231)
		(mid 87.214069 -236.846475)
		(end 86.937596 -236.913674)
		(width 0.088646)
		(layer "In4.Cu")
		(net "M_B_CPU1_SB_DQ<0>")
	)
	(arc
		(start 91.232482 -236.91342)
		(mid 90.956007 -236.8461)
		(end 90.68181 -236.922056)
		(width 0.088646)
		(layer "In4.Cu")
		(net "M_B_CPU1_SB_DQ<0>")
	)
	(arc
		(start 87.851742 -236.928406)
		(mid 87.669212 -236.97243)
		(end 87.488268 -236.92231)
		(width 0.088646)
		(layer "In4.Cu")
		(net "M_B_CPU1_SB_DQ<0>")
	)
	(arc
		(start 83.952842 -237.66145)
		(mid 83.934689 -237.660647)
		(end 83.91652 -237.660434)
		(width 0.088646)
		(layer "In4.Cu")
		(net "M_B_CPU1_SB_DQ<0>")
	)
	(arc
		(start 90.68181 -236.922056)
		(mid 90.494612 -236.972233)
		(end 90.307414 -236.922056)
		(width 0.088646)
		(layer "In4.Cu")
		(net "M_B_CPU1_SB_DQ<0>")
	)
	(arc
		(start 89.3572 -236.91596)
		(mid 89.079022 -236.846237)
		(end 88.802464 -236.922056)
		(width 0.088646)
		(layer "In4.Cu")
		(net "M_B_CPU1_SB_DQ<0>")
	)
	(arc
		(start 89.74201 -236.922056)
		(mid 89.554812 -236.972233)
		(end 89.367614 -236.922056)
		(width 0.088646)
		(layer "In4.Cu")
		(net "M_B_CPU1_SB_DQ<0>")
	)
	(arc
		(start 85.608668 -236.92231)
		(mid 85.334469 -236.846475)
		(end 85.057996 -236.913674)
		(width 0.088646)
		(layer "In4.Cu")
		(net "M_B_CPU1_SB_DQ<0>")
	)
	(arc
		(start 88.802464 -236.922056)
		(mid 88.615266 -236.972233)
		(end 88.428068 -236.922056)
		(width 0.088646)
		(layer "In4.Cu")
		(net "M_B_CPU1_SB_DQ<0>")
	)
	(arc
		(start 84.57311 -237.736126)
		(mid 84.385912 -237.786269)
		(end 84.198714 -237.736126)
		(width 0.088646)
		(layer "In4.Cu")
		(net "M_B_CPU1_SB_DQ<0>")
	)
	(segment
		(start 90.024712 -246.08663)
		(end 90.024966 -246.086376)
		(width 0.20066)
		(layer "F.Cu")
		(net "M_B_CPU1_SB_CS_N<3>")
	)
	(segment
		(start 90.024966 -246.086376)
		(end 90.024966 -245.55069)
		(width 0.20066)
		(layer "F.Cu")
		(net "M_B_CPU1_SB_CS_N<3>")
	)
	(segment
		(start 49.959514 -244.916706)
		(end 51.064414 -244.916706)
		(width 0.20066)
		(layer "F.Cu")
		(net "M_B_CPU1_SB_CS_N<3>")
	)
	(segment
		(start 84.588096 -245.234968)
		(end 84.573364 -245.226332)
		(width 0.088646)
		(layer "In2.Cu")
		(net "M_B_CPU1_SB_CS_N<3>")
	)
	(segment
		(start 51.52644 -243.77523)
		(end 51.52644 -244.45468)
		(width 0.18288)
		(layer "In2.Cu")
		(net "M_B_CPU1_SB_CS_N<3>")
	)
	(segment
		(start 53.874162 -244.731032)
		(end 52.804568 -244.731032)
		(width 0.18288)
		(layer "In2.Cu")
		(net "M_B_CPU1_SB_CS_N<3>")
	)
	(segment
		(start 58.038238 -243.871242)
		(end 57.845452 -243.678456)
		(width 0.18288)
		(layer "In2.Cu")
		(net "M_B_CPU1_SB_CS_N<3>")
	)
	(segment
		(start 55.31485 -243.544852)
		(end 55.148226 -243.711476)
		(width 0.18288)
		(layer "In2.Cu")
		(net "M_B_CPU1_SB_CS_N<3>")
	)
	(segment
		(start 56.921654 -244.383052)
		(end 56.761634 -244.543072)
		(width 0.18288)
		(layer "In2.Cu")
		(net "M_B_CPU1_SB_CS_N<3>")
	)
	(segment
		(start 55.148226 -244.33149)
		(end 54.988206 -244.49151)
		(width 0.18288)
		(layer "In2.Cu")
		(net "M_B_CPU1_SB_CS_N<3>")
	)
	(segment
		(start 58.20791 -244.499384)
		(end 58.038238 -244.329712)
		(width 0.18288)
		(layer "In2.Cu")
		(net "M_B_CPU1_SB_CS_N<3>")
	)
	(segment
		(start 63.532258 -244.55374)
		(end 63.15329 -244.174772)
		(width 0.18288)
		(layer "In2.Cu")
		(net "M_B_CPU1_SB_CS_N<3>")
	)
	(segment
		(start 59.874404 -244.298978)
		(end 59.874404 -244.043454)
		(width 0.18288)
		(layer "In2.Cu")
		(net "M_B_CPU1_SB_CS_N<3>")
	)
	(segment
		(start 87.958168 -245.226332)
		(end 87.943436 -245.234968)
		(width 0.088646)
		(layer "In2.Cu")
		(net "M_B_CPU1_SB_CS_N<3>")
	)
	(segment
		(start 83.76158 -245.302278)
		(end 83.535012 -245.528846)
		(width 0.088646)
		(layer "In2.Cu")
		(net "M_B_CPU1_SB_CS_N<3>")
	)
	(segment
		(start 73.087992 -245.704868)
		(end 72.242172 -245.704868)
		(width 0.18288)
		(layer "In2.Cu")
		(net "M_B_CPU1_SB_CS_N<3>")
	)
	(segment
		(start 55.931054 -243.704872)
		(end 55.771034 -243.544852)
		(width 0.18288)
		(layer "In2.Cu")
		(net "M_B_CPU1_SB_CS_N<3>")
	)
	(segment
		(start 55.931054 -244.376448)
		(end 55.931054 -243.704872)
		(width 0.18288)
		(layer "In2.Cu")
		(net "M_B_CPU1_SB_CS_N<3>")
	)
	(segment
		(start 54.113684 -244.49151)
		(end 53.874162 -244.731032)
		(width 0.18288)
		(layer "In2.Cu")
		(net "M_B_CPU1_SB_CS_N<3>")
	)
	(segment
		(start 66.924682 -244.139212)
		(end 66.731642 -244.332252)
		(width 0.18288)
		(layer "In2.Cu")
		(net "M_B_CPU1_SB_CS_N<3>")
	)
	(segment
		(start 83.916012 -245.302278)
		(end 83.76158 -245.302278)
		(width 0.088646)
		(layer "In2.Cu")
		(net "M_B_CPU1_SB_CS_N<3>")
	)
	(segment
		(start 67.71386 -244.820186)
		(end 67.52082 -244.627146)
		(width 0.18288)
		(layer "In2.Cu")
		(net "M_B_CPU1_SB_CS_N<3>")
	)
	(segment
		(start 65.7098 -244.29085)
		(end 64.41694 -244.29085)
		(width 0.18288)
		(layer "In2.Cu")
		(net "M_B_CPU1_SB_CS_N<3>")
	)
	(segment
		(start 52.352702 -244.279166)
		(end 52.352702 -243.74221)
		(width 0.18288)
		(layer "In2.Cu")
		(net "M_B_CPU1_SB_CS_N<3>")
	)
	(segment
		(start 73.264014 -245.528846)
		(end 73.087992 -245.704868)
		(width 0.18288)
		(layer "In2.Cu")
		(net "M_B_CPU1_SB_CS_N<3>")
	)
	(segment
		(start 66.731642 -244.332252)
		(end 66.731642 -244.627146)
		(width 0.18288)
		(layer "In2.Cu")
		(net "M_B_CPU1_SB_CS_N<3>")
	)
	(segment
		(start 88.332564 -245.226586)
		(end 88.332564 -245.226332)
		(width 0.088646)
		(layer "In2.Cu")
		(net "M_B_CPU1_SB_CS_N<3>")
	)
	(segment
		(start 51.71948 -243.58219)
		(end 51.52644 -243.77523)
		(width 0.18288)
		(layer "In2.Cu")
		(net "M_B_CPU1_SB_CS_N<3>")
	)
	(segment
		(start 52.352702 -243.74221)
		(end 52.192682 -243.58219)
		(width 0.18288)
		(layer "In2.Cu")
		(net "M_B_CPU1_SB_CS_N<3>")
	)
	(segment
		(start 61.368432 -244.49151)
		(end 61.01969 -244.840252)
		(width 0.18288)
		(layer "In2.Cu")
		(net "M_B_CPU1_SB_CS_N<3>")
	)
	(segment
		(start 59.09818 -244.297708)
		(end 58.896504 -244.499384)
		(width 0.18288)
		(layer "In2.Cu")
		(net "M_B_CPU1_SB_CS_N<3>")
	)
	(segment
		(start 72.242172 -245.704868)
		(end 71.35749 -244.820186)
		(width 0.18288)
		(layer "In2.Cu")
		(net "M_B_CPU1_SB_CS_N<3>")
	)
	(segment
		(start 89.647014 -245.657624)
		(end 89.272364 -245.875048)
		(width 0.088646)
		(layer "In2.Cu")
		(net "M_B_CPU1_SB_CS_N<3>")
	)
	(segment
		(start 66.538602 -244.820186)
		(end 66.239136 -244.820186)
		(width 0.18288)
		(layer "In2.Cu")
		(net "M_B_CPU1_SB_CS_N<3>")
	)
	(segment
		(start 83.535012 -245.528846)
		(end 83.158838 -245.528846)
		(width 0.088646)
		(layer "In2.Cu")
		(net "M_B_CPU1_SB_CS_N<3>")
	)
	(segment
		(start 55.771034 -243.544852)
		(end 55.31485 -243.544852)
		(width 0.18288)
		(layer "In2.Cu")
		(net "M_B_CPU1_SB_CS_N<3>")
	)
	(segment
		(start 87.018368 -245.226332)
		(end 87.003636 -245.234968)
		(width 0.088646)
		(layer "In2.Cu")
		(net "M_B_CPU1_SB_CS_N<3>")
	)
	(segment
		(start 88.897968 -245.875048)
		(end 88.611964 -245.709694)
		(width 0.088646)
		(layer "In2.Cu")
		(net "M_B_CPU1_SB_CS_N<3>")
	)
	(segment
		(start 59.2582 -243.883434)
		(end 59.09818 -244.043454)
		(width 0.18288)
		(layer "In2.Cu")
		(net "M_B_CPU1_SB_CS_N<3>")
	)
	(segment
		(start 67.52082 -244.332252)
		(end 67.32778 -244.139212)
		(width 0.18288)
		(layer "In2.Cu")
		(net "M_B_CPU1_SB_CS_N<3>")
	)
	(segment
		(start 67.52082 -244.627146)
		(end 67.52082 -244.332252)
		(width 0.18288)
		(layer "In2.Cu")
		(net "M_B_CPU1_SB_CS_N<3>")
	)
	(segment
		(start 67.32778 -244.139212)
		(end 66.924682 -244.139212)
		(width 0.18288)
		(layer "In2.Cu")
		(net "M_B_CPU1_SB_CS_N<3>")
	)
	(segment
		(start 66.239136 -244.820186)
		(end 65.7098 -244.29085)
		(width 0.18288)
		(layer "In2.Cu")
		(net "M_B_CPU1_SB_CS_N<3>")
	)
	(segment
		(start 56.921654 -243.838476)
		(end 56.921654 -244.383052)
		(width 0.18288)
		(layer "In2.Cu")
		(net "M_B_CPU1_SB_CS_N<3>")
	)
	(segment
		(start 63.15329 -244.174772)
		(end 62.685168 -244.174772)
		(width 0.18288)
		(layer "In2.Cu")
		(net "M_B_CPU1_SB_CS_N<3>")
	)
	(segment
		(start 59.874404 -244.043454)
		(end 59.714384 -243.883434)
		(width 0.18288)
		(layer "In2.Cu")
		(net "M_B_CPU1_SB_CS_N<3>")
	)
	(segment
		(start 60.415678 -244.840252)
		(end 59.874404 -244.298978)
		(width 0.18288)
		(layer "In2.Cu")
		(net "M_B_CPU1_SB_CS_N<3>")
	)
	(segment
		(start 71.35749 -244.820186)
		(end 67.71386 -244.820186)
		(width 0.18288)
		(layer "In2.Cu")
		(net "M_B_CPU1_SB_CS_N<3>")
	)
	(segment
		(start 90.024966 -245.55069)
		(end 89.647014 -245.657624)
		(width 0.088646)
		(layer "In2.Cu")
		(net "M_B_CPU1_SB_CS_N<3>")
	)
	(segment
		(start 58.038238 -244.329712)
		(end 58.038238 -243.871242)
		(width 0.18288)
		(layer "In2.Cu")
		(net "M_B_CPU1_SB_CS_N<3>")
	)
	(segment
		(start 56.097678 -244.543072)
		(end 55.931054 -244.376448)
		(width 0.18288)
		(layer "In2.Cu")
		(net "M_B_CPU1_SB_CS_N<3>")
	)
	(segment
		(start 62.685168 -244.174772)
		(end 62.36843 -244.49151)
		(width 0.18288)
		(layer "In2.Cu")
		(net "M_B_CPU1_SB_CS_N<3>")
	)
	(segment
		(start 57.081674 -243.678456)
		(end 56.921654 -243.838476)
		(width 0.18288)
		(layer "In2.Cu")
		(net "M_B_CPU1_SB_CS_N<3>")
	)
	(segment
		(start 64.41694 -244.29085)
		(end 64.15405 -244.55374)
		(width 0.18288)
		(layer "In2.Cu")
		(net "M_B_CPU1_SB_CS_N<3>")
	)
	(segment
		(start 58.896504 -244.499384)
		(end 58.20791 -244.499384)
		(width 0.18288)
		(layer "In2.Cu")
		(net "M_B_CPU1_SB_CS_N<3>")
	)
	(segment
		(start 66.731642 -244.627146)
		(end 66.538602 -244.820186)
		(width 0.18288)
		(layer "In2.Cu")
		(net "M_B_CPU1_SB_CS_N<3>")
	)
	(segment
		(start 59.714384 -243.883434)
		(end 59.2582 -243.883434)
		(width 0.18288)
		(layer "In2.Cu")
		(net "M_B_CPU1_SB_CS_N<3>")
	)
	(segment
		(start 55.148226 -243.711476)
		(end 55.148226 -244.33149)
		(width 0.18288)
		(layer "In2.Cu")
		(net "M_B_CPU1_SB_CS_N<3>")
	)
	(segment
		(start 54.988206 -244.49151)
		(end 54.113684 -244.49151)
		(width 0.18288)
		(layer "In2.Cu")
		(net "M_B_CPU1_SB_CS_N<3>")
	)
	(segment
		(start 51.52644 -244.45468)
		(end 51.064414 -244.916706)
		(width 0.18288)
		(layer "In2.Cu")
		(net "M_B_CPU1_SB_CS_N<3>")
	)
	(segment
		(start 62.36843 -244.49151)
		(end 61.368432 -244.49151)
		(width 0.18288)
		(layer "In2.Cu")
		(net "M_B_CPU1_SB_CS_N<3>")
	)
	(segment
		(start 56.761634 -244.543072)
		(end 56.097678 -244.543072)
		(width 0.18288)
		(layer "In2.Cu")
		(net "M_B_CPU1_SB_CS_N<3>")
	)
	(segment
		(start 61.01969 -244.840252)
		(end 60.415678 -244.840252)
		(width 0.18288)
		(layer "In2.Cu")
		(net "M_B_CPU1_SB_CS_N<3>")
	)
	(segment
		(start 57.845452 -243.678456)
		(end 57.081674 -243.678456)
		(width 0.18288)
		(layer "In2.Cu")
		(net "M_B_CPU1_SB_CS_N<3>")
	)
	(segment
		(start 85.527896 -245.234968)
		(end 85.513164 -245.226332)
		(width 0.088646)
		(layer "In2.Cu")
		(net "M_B_CPU1_SB_CS_N<3>")
	)
	(segment
		(start 52.192682 -243.58219)
		(end 51.71948 -243.58219)
		(width 0.18288)
		(layer "In2.Cu")
		(net "M_B_CPU1_SB_CS_N<3>")
	)
	(segment
		(start 64.15405 -244.55374)
		(end 63.532258 -244.55374)
		(width 0.18288)
		(layer "In2.Cu")
		(net "M_B_CPU1_SB_CS_N<3>")
	)
	(segment
		(start 52.804568 -244.731032)
		(end 52.352702 -244.279166)
		(width 0.18288)
		(layer "In2.Cu")
		(net "M_B_CPU1_SB_CS_N<3>")
	)
	(segment
		(start 83.158838 -245.528846)
		(end 73.264014 -245.528846)
		(width 0.18288)
		(layer "In2.Cu")
		(net "M_B_CPU1_SB_CS_N<3>")
	)
	(segment
		(start 59.09818 -244.043454)
		(end 59.09818 -244.297708)
		(width 0.18288)
		(layer "In2.Cu")
		(net "M_B_CPU1_SB_CS_N<3>")
	)
	(arc
		(start 87.003636 -245.234968)
		(mid 86.727161 -245.302288)
		(end 86.452964 -245.226332)
		(width 0.088646)
		(layer "In2.Cu")
		(net "M_B_CPU1_SB_CS_N<3>")
	)
	(arc
		(start 88.332564 -245.226332)
		(mid 88.145366 -245.176189)
		(end 87.958168 -245.226332)
		(width 0.088646)
		(layer "In2.Cu")
		(net "M_B_CPU1_SB_CS_N<3>")
	)
	(arc
		(start 89.272364 -245.875048)
		(mid 89.085166 -245.925225)
		(end 88.897968 -245.875048)
		(width 0.088646)
		(layer "In2.Cu")
		(net "M_B_CPU1_SB_CS_N<3>")
	)
	(arc
		(start 88.520016 -245.55069)
		(mid 88.469723 -245.363514)
		(end 88.332564 -245.226586)
		(width 0.088646)
		(layer "In2.Cu")
		(net "M_B_CPU1_SB_CS_N<3>")
	)
	(arc
		(start 84.198968 -245.226332)
		(mid 84.062495 -245.282966)
		(end 83.916012 -245.302278)
		(width 0.088646)
		(layer "In2.Cu")
		(net "M_B_CPU1_SB_CS_N<3>")
	)
	(arc
		(start 88.611964 -245.709694)
		(mid 88.544634 -245.642536)
		(end 88.520016 -245.55069)
		(width 0.088646)
		(layer "In2.Cu")
		(net "M_B_CPU1_SB_CS_N<3>")
	)
	(arc
		(start 85.513164 -245.226332)
		(mid 85.325966 -245.176189)
		(end 85.138768 -245.226332)
		(width 0.088646)
		(layer "In2.Cu")
		(net "M_B_CPU1_SB_CS_N<3>")
	)
	(arc
		(start 87.943436 -245.234968)
		(mid 87.666961 -245.302288)
		(end 87.392764 -245.226332)
		(width 0.088646)
		(layer "In2.Cu")
		(net "M_B_CPU1_SB_CS_N<3>")
	)
	(arc
		(start 86.452964 -245.226332)
		(mid 86.265766 -245.176189)
		(end 86.078568 -245.226332)
		(width 0.088646)
		(layer "In2.Cu")
		(net "M_B_CPU1_SB_CS_N<3>")
	)
	(arc
		(start 85.138768 -245.226332)
		(mid 84.864539 -245.302257)
		(end 84.588096 -245.234968)
		(width 0.088646)
		(layer "In2.Cu")
		(net "M_B_CPU1_SB_CS_N<3>")
	)
	(arc
		(start 84.573364 -245.226332)
		(mid 84.386166 -245.176189)
		(end 84.198968 -245.226332)
		(width 0.088646)
		(layer "In2.Cu")
		(net "M_B_CPU1_SB_CS_N<3>")
	)
	(arc
		(start 86.078568 -245.226332)
		(mid 85.804339 -245.302257)
		(end 85.527896 -245.234968)
		(width 0.088646)
		(layer "In2.Cu")
		(net "M_B_CPU1_SB_CS_N<3>")
	)
	(arc
		(start 87.392764 -245.226332)
		(mid 87.205566 -245.176189)
		(end 87.018368 -245.226332)
		(width 0.088646)
		(layer "In2.Cu")
		(net "M_B_CPU1_SB_CS_N<3>")
	)
	(segment
		(start 90.494866 -246.900446)
		(end 90.494612 -246.900192)
		(width 0.20066)
		(layer "F.Cu")
		(net "M_B_CPU1_SB_CS_N<2>")
	)
	(segment
		(start 45.859446 -245.76659)
		(end 46.964346 -245.76659)
		(width 0.20066)
		(layer "F.Cu")
		(net "M_B_CPU1_SB_CS_N<2>")
	)
	(segment
		(start 90.494612 -246.900192)
		(end 90.494612 -246.364506)
		(width 0.20066)
		(layer "F.Cu")
		(net "M_B_CPU1_SB_CS_N<2>")
	)
	(segment
		(start 51.453288 -245.419626)
		(end 51.37531 -245.341648)
		(width 0.18288)
		(layer "In2.Cu")
		(net "M_B_CPU1_SB_CS_N<2>")
	)
	(segment
		(start 88.817196 -246.048784)
		(end 88.516206 -245.875048)
		(width 0.088646)
		(layer "In2.Cu")
		(net "M_B_CPU1_SB_CS_N<2>")
	)
	(segment
		(start 54.699916 -245.560342)
		(end 54.389274 -245.560342)
		(width 0.18288)
		(layer "In2.Cu")
		(net "M_B_CPU1_SB_CS_N<2>")
	)
	(segment
		(start 52.485544 -245.419626)
		(end 51.453288 -245.419626)
		(width 0.18288)
		(layer "In2.Cu")
		(net "M_B_CPU1_SB_CS_N<2>")
	)
	(segment
		(start 56.66359 -245.33098)
		(end 56.421782 -245.089172)
		(width 0.18288)
		(layer "In2.Cu")
		(net "M_B_CPU1_SB_CS_N<2>")
	)
	(segment
		(start 50.484532 -245.341648)
		(end 50.2031 -245.62308)
		(width 0.18288)
		(layer "In2.Cu")
		(net "M_B_CPU1_SB_CS_N<2>")
	)
	(segment
		(start 59.453018 -245.352062)
		(end 59.431936 -245.33098)
		(width 0.18288)
		(layer "In2.Cu")
		(net "M_B_CPU1_SB_CS_N<2>")
	)
	(segment
		(start 50.2031 -245.62308)
		(end 49.813464 -245.62308)
		(width 0.18288)
		(layer "In2.Cu")
		(net "M_B_CPU1_SB_CS_N<2>")
	)
	(segment
		(start 72.006714 -246.222266)
		(end 71.12254 -245.338092)
		(width 0.18288)
		(layer "In2.Cu")
		(net "M_B_CPU1_SB_CS_N<2>")
	)
	(segment
		(start 83.50885 -245.874286)
		(end 83.140296 -245.874286)
		(width 0.088646)
		(layer "In2.Cu")
		(net "M_B_CPU1_SB_CS_N<2>")
	)
	(segment
		(start 62.576202 -245.089172)
		(end 62.313312 -245.352062)
		(width 0.18288)
		(layer "In2.Cu")
		(net "M_B_CPU1_SB_CS_N<2>")
	)
	(segment
		(start 49.515014 -245.32463)
		(end 48.585882 -245.32463)
		(width 0.18288)
		(layer "In2.Cu")
		(net "M_B_CPU1_SB_CS_N<2>")
	)
	(segment
		(start 59.431936 -245.33098)
		(end 56.66359 -245.33098)
		(width 0.18288)
		(layer "In2.Cu")
		(net "M_B_CPU1_SB_CS_N<2>")
	)
	(segment
		(start 73.441306 -245.874286)
		(end 73.093326 -246.222266)
		(width 0.18288)
		(layer "In2.Cu")
		(net "M_B_CPU1_SB_CS_N<2>")
	)
	(segment
		(start 55.171086 -245.089172)
		(end 54.699916 -245.560342)
		(width 0.18288)
		(layer "In2.Cu")
		(net "M_B_CPU1_SB_CS_N<2>")
	)
	(segment
		(start 47.455074 -244.345206)
		(end 47.455074 -245.275862)
		(width 0.18288)
		(layer "In2.Cu")
		(net "M_B_CPU1_SB_CS_N<2>")
	)
	(segment
		(start 48.425862 -244.323108)
		(end 48.25492 -244.152166)
		(width 0.18288)
		(layer "In2.Cu")
		(net "M_B_CPU1_SB_CS_N<2>")
	)
	(segment
		(start 83.916266 -245.799356)
		(end 83.58378 -245.799356)
		(width 0.088646)
		(layer "In2.Cu")
		(net "M_B_CPU1_SB_CS_N<2>")
	)
	(segment
		(start 62.313312 -245.352062)
		(end 59.453018 -245.352062)
		(width 0.18288)
		(layer "In2.Cu")
		(net "M_B_CPU1_SB_CS_N<2>")
	)
	(segment
		(start 48.425862 -245.16461)
		(end 48.425862 -244.323108)
		(width 0.18288)
		(layer "In2.Cu")
		(net "M_B_CPU1_SB_CS_N<2>")
	)
	(segment
		(start 54.389274 -245.560342)
		(end 54.17058 -245.341648)
		(width 0.18288)
		(layer "In2.Cu")
		(net "M_B_CPU1_SB_CS_N<2>")
	)
	(segment
		(start 89.770712 -246.056658)
		(end 89.742264 -246.040148)
		(width 0.088646)
		(layer "In2.Cu")
		(net "M_B_CPU1_SB_CS_N<2>")
	)
	(segment
		(start 48.25492 -244.152166)
		(end 47.648114 -244.152166)
		(width 0.18288)
		(layer "In2.Cu")
		(net "M_B_CPU1_SB_CS_N<2>")
	)
	(segment
		(start 83.140296 -245.874286)
		(end 73.441306 -245.874286)
		(width 0.18288)
		(layer "In2.Cu")
		(net "M_B_CPU1_SB_CS_N<2>")
	)
	(segment
		(start 51.37531 -245.341648)
		(end 50.484532 -245.341648)
		(width 0.18288)
		(layer "In2.Cu")
		(net "M_B_CPU1_SB_CS_N<2>")
	)
	(segment
		(start 73.093326 -246.222266)
		(end 72.006714 -246.222266)
		(width 0.18288)
		(layer "In2.Cu")
		(net "M_B_CPU1_SB_CS_N<2>")
	)
	(segment
		(start 63.898526 -245.089172)
		(end 62.576202 -245.089172)
		(width 0.18288)
		(layer "In2.Cu")
		(net "M_B_CPU1_SB_CS_N<2>")
	)
	(segment
		(start 90.494612 -246.364506)
		(end 89.770712 -246.056658)
		(width 0.088646)
		(layer "In2.Cu")
		(net "M_B_CPU1_SB_CS_N<2>")
	)
	(segment
		(start 64.147446 -245.338092)
		(end 63.898526 -245.089172)
		(width 0.18288)
		(layer "In2.Cu")
		(net "M_B_CPU1_SB_CS_N<2>")
	)
	(segment
		(start 52.563522 -245.341648)
		(end 52.485544 -245.419626)
		(width 0.18288)
		(layer "In2.Cu")
		(net "M_B_CPU1_SB_CS_N<2>")
	)
	(segment
		(start 83.58378 -245.799356)
		(end 83.50885 -245.874286)
		(width 0.088646)
		(layer "In2.Cu")
		(net "M_B_CPU1_SB_CS_N<2>")
	)
	(segment
		(start 54.17058 -245.341648)
		(end 52.563522 -245.341648)
		(width 0.18288)
		(layer "In2.Cu")
		(net "M_B_CPU1_SB_CS_N<2>")
	)
	(segment
		(start 56.421782 -245.089172)
		(end 55.171086 -245.089172)
		(width 0.18288)
		(layer "In2.Cu")
		(net "M_B_CPU1_SB_CS_N<2>")
	)
	(segment
		(start 47.648114 -244.152166)
		(end 47.455074 -244.345206)
		(width 0.18288)
		(layer "In2.Cu")
		(net "M_B_CPU1_SB_CS_N<2>")
	)
	(segment
		(start 71.12254 -245.338092)
		(end 64.147446 -245.338092)
		(width 0.18288)
		(layer "In2.Cu")
		(net "M_B_CPU1_SB_CS_N<2>")
	)
	(segment
		(start 49.813464 -245.62308)
		(end 49.515014 -245.32463)
		(width 0.18288)
		(layer "In2.Cu")
		(net "M_B_CPU1_SB_CS_N<2>")
	)
	(segment
		(start 47.455074 -245.275862)
		(end 46.964346 -245.76659)
		(width 0.18288)
		(layer "In2.Cu")
		(net "M_B_CPU1_SB_CS_N<2>")
	)
	(segment
		(start 48.585882 -245.32463)
		(end 48.425862 -245.16461)
		(width 0.18288)
		(layer "In2.Cu")
		(net "M_B_CPU1_SB_CS_N<2>")
	)
	(arc
		(start 87.392764 -245.875048)
		(mid 87.205566 -245.925191)
		(end 87.018368 -245.875048)
		(width 0.088646)
		(layer "In2.Cu")
		(net "M_B_CPU1_SB_CS_N<2>")
	)
	(arc
		(start 87.958168 -245.875048)
		(mid 87.675466 -245.799272)
		(end 87.392764 -245.875048)
		(width 0.088646)
		(layer "In2.Cu")
		(net "M_B_CPU1_SB_CS_N<2>")
	)
	(arc
		(start 87.018368 -245.875048)
		(mid 86.735666 -245.799272)
		(end 86.452964 -245.875048)
		(width 0.088646)
		(layer "In2.Cu")
		(net "M_B_CPU1_SB_CS_N<2>")
	)
	(arc
		(start 84.573364 -245.875048)
		(mid 84.386166 -245.925191)
		(end 84.198968 -245.875048)
		(width 0.088646)
		(layer "In2.Cu")
		(net "M_B_CPU1_SB_CS_N<2>")
	)
	(arc
		(start 88.332564 -245.875048)
		(mid 88.145366 -245.925225)
		(end 87.958168 -245.875048)
		(width 0.088646)
		(layer "In2.Cu")
		(net "M_B_CPU1_SB_CS_N<2>")
	)
	(arc
		(start 89.36482 -246.041672)
		(mid 89.091935 -246.115934)
		(end 88.817196 -246.048784)
		(width 0.088646)
		(layer "In2.Cu")
		(net "M_B_CPU1_SB_CS_N<2>")
	)
	(arc
		(start 84.198968 -245.875048)
		(mid 84.062599 -245.818606)
		(end 83.916266 -245.799356)
		(width 0.088646)
		(layer "In2.Cu")
		(net "M_B_CPU1_SB_CS_N<2>")
	)
	(arc
		(start 85.513164 -245.875048)
		(mid 85.325966 -245.925191)
		(end 85.138768 -245.875048)
		(width 0.088646)
		(layer "In2.Cu")
		(net "M_B_CPU1_SB_CS_N<2>")
	)
	(arc
		(start 86.078568 -245.875048)
		(mid 85.795866 -245.799272)
		(end 85.513164 -245.875048)
		(width 0.088646)
		(layer "In2.Cu")
		(net "M_B_CPU1_SB_CS_N<2>")
	)
	(arc
		(start 89.742264 -246.040148)
		(mid 89.563478 -245.990031)
		(end 89.3826 -246.03202)
		(width 0.088646)
		(layer "In2.Cu")
		(net "M_B_CPU1_SB_CS_N<2>")
	)
	(arc
		(start 89.3826 -246.03202)
		(mid 89.373645 -246.036726)
		(end 89.36482 -246.041672)
		(width 0.088646)
		(layer "In2.Cu")
		(net "M_B_CPU1_SB_CS_N<2>")
	)
	(arc
		(start 86.452964 -245.875048)
		(mid 86.265766 -245.925191)
		(end 86.078568 -245.875048)
		(width 0.088646)
		(layer "In2.Cu")
		(net "M_B_CPU1_SB_CS_N<2>")
	)
	(arc
		(start 88.516206 -245.875048)
		(mid 88.424368 -245.850376)
		(end 88.332564 -245.875048)
		(width 0.088646)
		(layer "In2.Cu")
		(net "M_B_CPU1_SB_CS_N<2>")
	)
	(arc
		(start 85.138768 -245.875048)
		(mid 84.856066 -245.799272)
		(end 84.573364 -245.875048)
		(width 0.088646)
		(layer "In2.Cu")
		(net "M_B_CPU1_SB_CS_N<2>")
	)
	(segment
		(start 89.084912 -246.08663)
		(end 89.085166 -246.086376)
		(width 0.20066)
		(layer "F.Cu")
		(net "M_B_CPU1_SB_CS_N<1>")
	)
	(segment
		(start 42.415714 -244.916706)
		(end 43.520614 -244.916706)
		(width 0.20066)
		(layer "F.Cu")
		(net "M_B_CPU1_SB_CS_N<1>")
	)
	(segment
		(start 89.085166 -246.086376)
		(end 89.085166 -245.55069)
		(width 0.20066)
		(layer "F.Cu")
		(net "M_B_CPU1_SB_CS_N<1>")
	)
	(segment
		(start 55.849774 -242.14328)
		(end 55.68315 -241.976656)
		(width 0.18288)
		(layer "In2.Cu")
		(net "M_B_CPU1_SB_CS_N<1>")
	)
	(segment
		(start 51.613816 -241.941858)
		(end 49.101756 -241.941858)
		(width 0.18288)
		(layer "In2.Cu")
		(net "M_B_CPU1_SB_CS_N<1>")
	)
	(segment
		(start 69.677534 -244.293898)
		(end 69.484494 -244.100858)
		(width 0.18288)
		(layer "In2.Cu")
		(net "M_B_CPU1_SB_CS_N<1>")
	)
	(segment
		(start 68.970144 -243.618258)
		(end 68.777104 -243.811298)
		(width 0.18288)
		(layer "In2.Cu")
		(net "M_B_CPU1_SB_CS_N<1>")
	)
	(segment
		(start 69.291454 -243.618258)
		(end 68.970144 -243.618258)
		(width 0.18288)
		(layer "In2.Cu")
		(net "M_B_CPU1_SB_CS_N<1>")
	)
	(segment
		(start 51.942746 -241.612928)
		(end 51.613816 -241.941858)
		(width 0.18288)
		(layer "In2.Cu")
		(net "M_B_CPU1_SB_CS_N<1>")
	)
	(segment
		(start 72.474074 -245.183406)
		(end 70.908926 -243.618258)
		(width 0.18288)
		(layer "In2.Cu")
		(net "M_B_CPU1_SB_CS_N<1>")
	)
	(segment
		(start 85.99805 -245.052596)
		(end 85.983318 -245.061232)
		(width 0.088646)
		(layer "In2.Cu")
		(net "M_B_CPU1_SB_CS_N<1>")
	)
	(segment
		(start 60.196476 -243.641626)
		(end 59.474862 -242.920012)
		(width 0.18288)
		(layer "In2.Cu")
		(net "M_B_CPU1_SB_CS_N<1>")
	)
	(segment
		(start 48.941736 -242.89131)
		(end 48.748696 -243.08435)
		(width 0.18288)
		(layer "In2.Cu")
		(net "M_B_CPU1_SB_CS_N<1>")
	)
	(segment
		(start 70.012052 -244.293898)
		(end 69.677534 -244.293898)
		(width 0.18288)
		(layer "In2.Cu")
		(net "M_B_CPU1_SB_CS_N<1>")
	)
	(segment
		(start 53.751734 -242.791742)
		(end 53.591714 -242.631722)
		(width 0.18288)
		(layer "In2.Cu")
		(net "M_B_CPU1_SB_CS_N<1>")
	)
	(segment
		(start 55.034434 -242.136676)
		(end 55.034434 -242.631722)
		(width 0.18288)
		(layer "In2.Cu")
		(net "M_B_CPU1_SB_CS_N<1>")
	)
	(segment
		(start 70.398132 -243.618258)
		(end 70.205092 -243.811298)
		(width 0.18288)
		(layer "In2.Cu")
		(net "M_B_CPU1_SB_CS_N<1>")
	)
	(segment
		(start 64.324992 -243.778278)
		(end 64.18834 -243.641626)
		(width 0.18288)
		(layer "In2.Cu")
		(net "M_B_CPU1_SB_CS_N<1>")
	)
	(segment
		(start 68.03517 -244.110764)
		(end 68.03517 -243.811298)
		(width 0.18288)
		(layer "In2.Cu")
		(net "M_B_CPU1_SB_CS_N<1>")
	)
	(segment
		(start 69.484494 -244.100858)
		(end 69.484494 -243.811298)
		(width 0.18288)
		(layer "In2.Cu")
		(net "M_B_CPU1_SB_CS_N<1>")
	)
	(segment
		(start 68.777104 -244.110764)
		(end 68.584064 -244.303804)
		(width 0.18288)
		(layer "In2.Cu")
		(net "M_B_CPU1_SB_CS_N<1>")
	)
	(segment
		(start 44.38142 -243.0526)
		(end 44.695872 -243.0526)
		(width 0.18288)
		(layer "In2.Cu")
		(net "M_B_CPU1_SB_CS_N<1>")
	)
	(segment
		(start 45.438568 -242.12804)
		(end 45.238924 -241.928396)
		(width 0.18288)
		(layer "In2.Cu")
		(net "M_B_CPU1_SB_CS_N<1>")
	)
	(segment
		(start 44.18838 -242.85956)
		(end 44.38142 -243.0526)
		(width 0.18288)
		(layer "In2.Cu")
		(net "M_B_CPU1_SB_CS_N<1>")
	)
	(segment
		(start 84.668614 -245.060978)
		(end 84.653882 -245.052342)
		(width 0.088646)
		(layer "In2.Cu")
		(net "M_B_CPU1_SB_CS_N<1>")
	)
	(segment
		(start 44.38142 -243.75618)
		(end 44.18838 -243.94922)
		(width 0.18288)
		(layer "In2.Cu")
		(net "M_B_CPU1_SB_CS_N<1>")
	)
	(segment
		(start 52.723288 -242.12042)
		(end 52.215796 -241.612928)
		(width 0.18288)
		(layer "In2.Cu")
		(net "M_B_CPU1_SB_CS_N<1>")
	)
	(segment
		(start 55.849774 -242.598702)
		(end 55.849774 -242.14328)
		(width 0.18288)
		(layer "In2.Cu")
		(net "M_B_CPU1_SB_CS_N<1>")
	)
	(segment
		(start 59.474862 -242.920012)
		(end 59.248294 -242.920012)
		(width 0.18288)
		(layer "In2.Cu")
		(net "M_B_CPU1_SB_CS_N<1>")
	)
	(segment
		(start 46.206156 -242.793012)
		(end 46.089824 -242.67668)
		(width 0.18288)
		(layer "In2.Cu")
		(net "M_B_CPU1_SB_CS_N<1>")
	)
	(segment
		(start 85.608414 -245.060978)
		(end 85.593682 -245.052342)
		(width 0.088646)
		(layer "In2.Cu")
		(net "M_B_CPU1_SB_CS_N<1>")
	)
	(segment
		(start 68.584064 -244.303804)
		(end 68.22821 -244.303804)
		(width 0.18288)
		(layer "In2.Cu")
		(net "M_B_CPU1_SB_CS_N<1>")
	)
	(segment
		(start 88.442546 -245.069614)
		(end 88.413082 -245.052342)
		(width 0.088646)
		(layer "In2.Cu")
		(net "M_B_CPU1_SB_CS_N<1>")
	)
	(segment
		(start 86.93785 -245.052596)
		(end 86.923118 -245.061232)
		(width 0.088646)
		(layer "In2.Cu")
		(net "M_B_CPU1_SB_CS_N<1>")
	)
	(segment
		(start 58.340244 -242.791742)
		(end 56.042814 -242.791742)
		(width 0.18288)
		(layer "In2.Cu")
		(net "M_B_CPU1_SB_CS_N<1>")
	)
	(segment
		(start 45.438568 -242.51666)
		(end 45.438568 -242.12804)
		(width 0.18288)
		(layer "In2.Cu")
		(net "M_B_CPU1_SB_CS_N<1>")
	)
	(segment
		(start 53.591714 -242.28044)
		(end 53.431694 -242.12042)
		(width 0.18288)
		(layer "In2.Cu")
		(net "M_B_CPU1_SB_CS_N<1>")
	)
	(segment
		(start 45.598588 -242.67668)
		(end 45.438568 -242.51666)
		(width 0.18288)
		(layer "In2.Cu")
		(net "M_B_CPU1_SB_CS_N<1>")
	)
	(segment
		(start 44.888912 -243.24564)
		(end 44.888912 -243.56314)
		(width 0.18288)
		(layer "In2.Cu")
		(net "M_B_CPU1_SB_CS_N<1>")
	)
	(segment
		(start 53.431694 -242.12042)
		(end 52.723288 -242.12042)
		(width 0.18288)
		(layer "In2.Cu")
		(net "M_B_CPU1_SB_CS_N<1>")
	)
	(segment
		(start 47.79772 -243.08435)
		(end 47.506382 -242.793012)
		(width 0.18288)
		(layer "In2.Cu")
		(net "M_B_CPU1_SB_CS_N<1>")
	)
	(segment
		(start 55.68315 -241.976656)
		(end 55.194454 -241.976656)
		(width 0.18288)
		(layer "In2.Cu")
		(net "M_B_CPU1_SB_CS_N<1>")
	)
	(segment
		(start 88.457278 -245.077996)
		(end 88.442546 -245.069614)
		(width 0.088646)
		(layer "In2.Cu")
		(net "M_B_CPU1_SB_CS_N<1>")
	)
	(segment
		(start 59.248294 -242.920012)
		(end 58.952892 -243.215414)
		(width 0.18288)
		(layer "In2.Cu")
		(net "M_B_CPU1_SB_CS_N<1>")
	)
	(segment
		(start 89.085166 -245.55069)
		(end 88.457278 -245.077996)
		(width 0.088646)
		(layer "In2.Cu")
		(net "M_B_CPU1_SB_CS_N<1>")
	)
	(segment
		(start 46.089824 -242.67668)
		(end 45.598588 -242.67668)
		(width 0.18288)
		(layer "In2.Cu")
		(net "M_B_CPU1_SB_CS_N<1>")
	)
	(segment
		(start 52.215796 -241.612928)
		(end 51.942746 -241.612928)
		(width 0.18288)
		(layer "In2.Cu")
		(net "M_B_CPU1_SB_CS_N<1>")
	)
	(segment
		(start 44.888912 -243.56314)
		(end 44.695872 -243.75618)
		(width 0.18288)
		(layer "In2.Cu")
		(net "M_B_CPU1_SB_CS_N<1>")
	)
	(segment
		(start 49.101756 -241.941858)
		(end 48.941736 -242.101878)
		(width 0.18288)
		(layer "In2.Cu")
		(net "M_B_CPU1_SB_CS_N<1>")
	)
	(segment
		(start 70.205092 -244.100858)
		(end 70.012052 -244.293898)
		(width 0.18288)
		(layer "In2.Cu")
		(net "M_B_CPU1_SB_CS_N<1>")
	)
	(segment
		(start 68.777104 -243.811298)
		(end 68.777104 -244.110764)
		(width 0.18288)
		(layer "In2.Cu")
		(net "M_B_CPU1_SB_CS_N<1>")
	)
	(segment
		(start 83.676236 -245.112032)
		(end 83.604862 -245.183406)
		(width 0.088646)
		(layer "In2.Cu")
		(net "M_B_CPU1_SB_CS_N<1>")
	)
	(segment
		(start 58.763916 -243.215414)
		(end 58.340244 -242.791742)
		(width 0.18288)
		(layer "In2.Cu")
		(net "M_B_CPU1_SB_CS_N<1>")
	)
	(segment
		(start 70.205092 -243.811298)
		(end 70.205092 -244.100858)
		(width 0.18288)
		(layer "In2.Cu")
		(net "M_B_CPU1_SB_CS_N<1>")
	)
	(segment
		(start 54.874414 -242.791742)
		(end 53.751734 -242.791742)
		(width 0.18288)
		(layer "In2.Cu")
		(net "M_B_CPU1_SB_CS_N<1>")
	)
	(segment
		(start 69.484494 -243.811298)
		(end 69.291454 -243.618258)
		(width 0.18288)
		(layer "In2.Cu")
		(net "M_B_CPU1_SB_CS_N<1>")
	)
	(segment
		(start 44.18838 -244.24894)
		(end 43.520614 -244.916706)
		(width 0.18288)
		(layer "In2.Cu")
		(net "M_B_CPU1_SB_CS_N<1>")
	)
	(segment
		(start 58.952892 -243.215414)
		(end 58.763916 -243.215414)
		(width 0.18288)
		(layer "In2.Cu")
		(net "M_B_CPU1_SB_CS_N<1>")
	)
	(segment
		(start 53.591714 -242.631722)
		(end 53.591714 -242.28044)
		(width 0.18288)
		(layer "In2.Cu")
		(net "M_B_CPU1_SB_CS_N<1>")
	)
	(segment
		(start 48.941736 -242.101878)
		(end 48.941736 -242.89131)
		(width 0.18288)
		(layer "In2.Cu")
		(net "M_B_CPU1_SB_CS_N<1>")
	)
	(segment
		(start 67.84213 -243.618258)
		(end 65.956688 -243.618258)
		(width 0.18288)
		(layer "In2.Cu")
		(net "M_B_CPU1_SB_CS_N<1>")
	)
	(segment
		(start 44.18838 -242.16106)
		(end 44.18838 -242.85956)
		(width 0.18288)
		(layer "In2.Cu")
		(net "M_B_CPU1_SB_CS_N<1>")
	)
	(segment
		(start 55.034434 -242.631722)
		(end 54.874414 -242.791742)
		(width 0.18288)
		(layer "In2.Cu")
		(net "M_B_CPU1_SB_CS_N<1>")
	)
	(segment
		(start 68.03517 -243.811298)
		(end 67.84213 -243.618258)
		(width 0.18288)
		(layer "In2.Cu")
		(net "M_B_CPU1_SB_CS_N<1>")
	)
	(segment
		(start 70.908926 -243.618258)
		(end 70.398132 -243.618258)
		(width 0.18288)
		(layer "In2.Cu")
		(net "M_B_CPU1_SB_CS_N<1>")
	)
	(segment
		(start 65.796668 -243.778278)
		(end 64.324992 -243.778278)
		(width 0.18288)
		(layer "In2.Cu")
		(net "M_B_CPU1_SB_CS_N<1>")
	)
	(segment
		(start 64.18834 -243.641626)
		(end 60.196476 -243.641626)
		(width 0.18288)
		(layer "In2.Cu")
		(net "M_B_CPU1_SB_CS_N<1>")
	)
	(segment
		(start 44.18838 -243.94922)
		(end 44.18838 -244.24894)
		(width 0.18288)
		(layer "In2.Cu")
		(net "M_B_CPU1_SB_CS_N<1>")
	)
	(segment
		(start 83.916012 -245.112032)
		(end 83.676236 -245.112032)
		(width 0.088646)
		(layer "In2.Cu")
		(net "M_B_CPU1_SB_CS_N<1>")
	)
	(segment
		(start 68.22821 -244.303804)
		(end 68.03517 -244.110764)
		(width 0.18288)
		(layer "In2.Cu")
		(net "M_B_CPU1_SB_CS_N<1>")
	)
	(segment
		(start 45.238924 -241.928396)
		(end 44.421044 -241.928396)
		(width 0.18288)
		(layer "In2.Cu")
		(net "M_B_CPU1_SB_CS_N<1>")
	)
	(segment
		(start 83.604862 -245.183406)
		(end 83.140296 -245.183406)
		(width 0.088646)
		(layer "In2.Cu")
		(net "M_B_CPU1_SB_CS_N<1>")
	)
	(segment
		(start 56.042814 -242.791742)
		(end 55.849774 -242.598702)
		(width 0.18288)
		(layer "In2.Cu")
		(net "M_B_CPU1_SB_CS_N<1>")
	)
	(segment
		(start 47.506382 -242.793012)
		(end 46.206156 -242.793012)
		(width 0.18288)
		(layer "In2.Cu")
		(net "M_B_CPU1_SB_CS_N<1>")
	)
	(segment
		(start 87.86241 -245.060978)
		(end 87.862918 -245.061232)
		(width 0.088646)
		(layer "In2.Cu")
		(net "M_B_CPU1_SB_CS_N<1>")
	)
	(segment
		(start 65.956688 -243.618258)
		(end 65.796668 -243.778278)
		(width 0.18288)
		(layer "In2.Cu")
		(net "M_B_CPU1_SB_CS_N<1>")
	)
	(segment
		(start 44.695872 -243.75618)
		(end 44.38142 -243.75618)
		(width 0.18288)
		(layer "In2.Cu")
		(net "M_B_CPU1_SB_CS_N<1>")
	)
	(segment
		(start 44.421044 -241.928396)
		(end 44.18838 -242.16106)
		(width 0.18288)
		(layer "In2.Cu")
		(net "M_B_CPU1_SB_CS_N<1>")
	)
	(segment
		(start 44.695872 -243.0526)
		(end 44.888912 -243.24564)
		(width 0.18288)
		(layer "In2.Cu")
		(net "M_B_CPU1_SB_CS_N<1>")
	)
	(segment
		(start 55.194454 -241.976656)
		(end 55.034434 -242.136676)
		(width 0.18288)
		(layer "In2.Cu")
		(net "M_B_CPU1_SB_CS_N<1>")
	)
	(segment
		(start 85.983318 -245.061232)
		(end 85.98281 -245.060978)
		(width 0.088646)
		(layer "In2.Cu")
		(net "M_B_CPU1_SB_CS_N<1>")
	)
	(segment
		(start 48.748696 -243.08435)
		(end 47.79772 -243.08435)
		(width 0.18288)
		(layer "In2.Cu")
		(net "M_B_CPU1_SB_CS_N<1>")
	)
	(segment
		(start 83.140296 -245.183406)
		(end 72.474074 -245.183406)
		(width 0.18288)
		(layer "In2.Cu")
		(net "M_B_CPU1_SB_CS_N<1>")
	)
	(arc
		(start 84.10321 -245.060978)
		(mid 84.012974 -245.098848)
		(end 83.916012 -245.112032)
		(width 0.088646)
		(layer "In2.Cu")
		(net "M_B_CPU1_SB_CS_N<1>")
	)
	(arc
		(start 85.593682 -245.052342)
		(mid 85.317241 -244.985176)
		(end 85.04301 -245.060978)
		(width 0.088646)
		(layer "In2.Cu")
		(net "M_B_CPU1_SB_CS_N<1>")
	)
	(arc
		(start 87.488522 -245.061232)
		(mid 87.214323 -244.985397)
		(end 86.93785 -245.052596)
		(width 0.088646)
		(layer "In2.Cu")
		(net "M_B_CPU1_SB_CS_N<1>")
	)
	(arc
		(start 85.04301 -245.060978)
		(mid 84.855812 -245.111121)
		(end 84.668614 -245.060978)
		(width 0.088646)
		(layer "In2.Cu")
		(net "M_B_CPU1_SB_CS_N<1>")
	)
	(arc
		(start 86.923118 -245.061232)
		(mid 86.73592 -245.111375)
		(end 86.548722 -245.061232)
		(width 0.088646)
		(layer "In2.Cu")
		(net "M_B_CPU1_SB_CS_N<1>")
	)
	(arc
		(start 86.548722 -245.061232)
		(mid 86.274523 -244.985397)
		(end 85.99805 -245.052596)
		(width 0.088646)
		(layer "In2.Cu")
		(net "M_B_CPU1_SB_CS_N<1>")
	)
	(arc
		(start 87.862918 -245.061232)
		(mid 87.67572 -245.111375)
		(end 87.488522 -245.061232)
		(width 0.088646)
		(layer "In2.Cu")
		(net "M_B_CPU1_SB_CS_N<1>")
	)
	(arc
		(start 88.413082 -245.052342)
		(mid 88.136641 -244.985176)
		(end 87.86241 -245.060978)
		(width 0.088646)
		(layer "In2.Cu")
		(net "M_B_CPU1_SB_CS_N<1>")
	)
	(arc
		(start 84.653882 -245.052342)
		(mid 84.377441 -244.985176)
		(end 84.10321 -245.060978)
		(width 0.088646)
		(layer "In2.Cu")
		(net "M_B_CPU1_SB_CS_N<1>")
	)
	(arc
		(start 85.98281 -245.060978)
		(mid 85.795612 -245.111121)
		(end 85.608414 -245.060978)
		(width 0.088646)
		(layer "In2.Cu")
		(net "M_B_CPU1_SB_CS_N<1>")
	)
	(segment
		(start 38.315646 -245.76659)
		(end 39.420546 -245.76659)
		(width 0.20066)
		(layer "F.Cu")
		(net "M_B_CPU1_SB_CS_N<0>")
	)
	(segment
		(start 88.615012 -246.900192)
		(end 88.615012 -246.364506)
		(width 0.20066)
		(layer "F.Cu")
		(net "M_B_CPU1_SB_CS_N<0>")
	)
	(segment
		(start 88.615266 -246.900446)
		(end 88.615012 -246.900192)
		(width 0.20066)
		(layer "F.Cu")
		(net "M_B_CPU1_SB_CS_N<0>")
	)
	(segment
		(start 55.678578 -245.679976)
		(end 55.39867 -245.679976)
		(width 0.18288)
		(layer "In2.Cu")
		(net "M_B_CPU1_SB_CS_N<0>")
	)
	(segment
		(start 52.347368 -245.973092)
		(end 51.480974 -245.973092)
		(width 0.18288)
		(layer "In2.Cu")
		(net "M_B_CPU1_SB_CS_N<0>")
	)
	(segment
		(start 41.766236 -246.19204)
		(end 41.52646 -246.19204)
		(width 0.18288)
		(layer "In2.Cu")
		(net "M_B_CPU1_SB_CS_N<0>")
	)
	(segment
		(start 40.27551 -246.854218)
		(end 40.27551 -245.97106)
		(width 0.18288)
		(layer "In2.Cu")
		(net "M_B_CPU1_SB_CS_N<0>")
	)
	(segment
		(start 66.026538 -246.259096)
		(end 65.618614 -245.851172)
		(width 0.18288)
		(layer "In2.Cu")
		(net "M_B_CPU1_SB_CS_N<0>")
	)
	(segment
		(start 56.907938 -245.92407)
		(end 56.6293 -246.202708)
		(width 0.18288)
		(layer "In2.Cu")
		(net "M_B_CPU1_SB_CS_N<0>")
	)
	(segment
		(start 83.916266 -245.989602)
		(end 83.750658 -245.989602)
		(width 0.088646)
		(layer "In2.Cu")
		(net "M_B_CPU1_SB_CS_N<0>")
	)
	(segment
		(start 47.46498 -246.191532)
		(end 45.065696 -246.191532)
		(width 0.18288)
		(layer "In2.Cu")
		(net "M_B_CPU1_SB_CS_N<0>")
	)
	(segment
		(start 40.07104 -245.76659)
		(end 39.420546 -245.76659)
		(width 0.18288)
		(layer "In2.Cu")
		(net "M_B_CPU1_SB_CS_N<0>")
	)
	(segment
		(start 66.730118 -245.851934)
		(end 66.322956 -246.259096)
		(width 0.18288)
		(layer "In2.Cu")
		(net "M_B_CPU1_SB_CS_N<0>")
	)
	(segment
		(start 42.79773 -245.576852)
		(end 42.60469 -245.383812)
		(width 0.18288)
		(layer "In2.Cu")
		(net "M_B_CPU1_SB_CS_N<0>")
	)
	(segment
		(start 73.818242 -246.219726)
		(end 73.29805 -246.739918)
		(width 0.18288)
		(layer "In2.Cu")
		(net "M_B_CPU1_SB_CS_N<0>")
	)
	(segment
		(start 70.70598 -245.851934)
		(end 66.730118 -245.851934)
		(width 0.18288)
		(layer "In2.Cu")
		(net "M_B_CPU1_SB_CS_N<0>")
	)
	(segment
		(start 60.387738 -246.515382)
		(end 60.043568 -246.171212)
		(width 0.18288)
		(layer "In2.Cu")
		(net "M_B_CPU1_SB_CS_N<0>")
	)
	(segment
		(start 88.615012 -246.364506)
		(end 88.615012 -246.364252)
		(width 0.088646)
		(layer "In2.Cu")
		(net "M_B_CPU1_SB_CS_N<0>")
	)
	(segment
		(start 88.615012 -246.364252)
		(end 87.89162 -246.057166)
		(width 0.088646)
		(layer "In2.Cu")
		(net "M_B_CPU1_SB_CS_N<0>")
	)
	(segment
		(start 83.14055 -246.219726)
		(end 73.818242 -246.219726)
		(width 0.18288)
		(layer "In2.Cu")
		(net "M_B_CPU1_SB_CS_N<0>")
	)
	(segment
		(start 41.180258 -247.047512)
		(end 40.468804 -247.047512)
		(width 0.18288)
		(layer "In2.Cu")
		(net "M_B_CPU1_SB_CS_N<0>")
	)
	(segment
		(start 42.79773 -245.999)
		(end 42.79773 -245.576852)
		(width 0.18288)
		(layer "In2.Cu")
		(net "M_B_CPU1_SB_CS_N<0>")
	)
	(segment
		(start 59.39663 -246.171212)
		(end 59.254898 -246.312944)
		(width 0.18288)
		(layer "In2.Cu")
		(net "M_B_CPU1_SB_CS_N<0>")
	)
	(segment
		(start 59.254898 -246.312944)
		(end 58.465974 -246.312944)
		(width 0.18288)
		(layer "In2.Cu")
		(net "M_B_CPU1_SB_CS_N<0>")
	)
	(segment
		(start 83.750658 -245.989602)
		(end 83.520534 -246.219726)
		(width 0.088646)
		(layer "In2.Cu")
		(net "M_B_CPU1_SB_CS_N<0>")
	)
	(segment
		(start 51.262534 -246.191532)
		(end 49.082706 -246.191532)
		(width 0.18288)
		(layer "In2.Cu")
		(net "M_B_CPU1_SB_CS_N<0>")
	)
	(segment
		(start 41.959276 -245.576852)
		(end 41.959276 -245.999)
		(width 0.18288)
		(layer "In2.Cu")
		(net "M_B_CPU1_SB_CS_N<0>")
	)
	(segment
		(start 43.765978 -246.209312)
		(end 43.008042 -246.209312)
		(width 0.18288)
		(layer "In2.Cu")
		(net "M_B_CPU1_SB_CS_N<0>")
	)
	(segment
		(start 41.52646 -246.19204)
		(end 41.36644 -246.35206)
		(width 0.18288)
		(layer "In2.Cu")
		(net "M_B_CPU1_SB_CS_N<0>")
	)
	(segment
		(start 42.152316 -245.383812)
		(end 41.959276 -245.576852)
		(width 0.18288)
		(layer "In2.Cu")
		(net "M_B_CPU1_SB_CS_N<0>")
	)
	(segment
		(start 65.618614 -245.851172)
		(end 64.529208 -245.851172)
		(width 0.18288)
		(layer "In2.Cu")
		(net "M_B_CPU1_SB_CS_N<0>")
	)
	(segment
		(start 58.0771 -245.92407)
		(end 56.907938 -245.92407)
		(width 0.18288)
		(layer "In2.Cu")
		(net "M_B_CPU1_SB_CS_N<0>")
	)
	(segment
		(start 66.322956 -246.259096)
		(end 66.026538 -246.259096)
		(width 0.18288)
		(layer "In2.Cu")
		(net "M_B_CPU1_SB_CS_N<0>")
	)
	(segment
		(start 56.20131 -246.202708)
		(end 55.678578 -245.679976)
		(width 0.18288)
		(layer "In2.Cu")
		(net "M_B_CPU1_SB_CS_N<0>")
	)
	(segment
		(start 64.13627 -246.24411)
		(end 63.75908 -246.24411)
		(width 0.18288)
		(layer "In2.Cu")
		(net "M_B_CPU1_SB_CS_N<0>")
	)
	(segment
		(start 47.85106 -247.03786)
		(end 47.65802 -246.84482)
		(width 0.18288)
		(layer "In2.Cu")
		(net "M_B_CPU1_SB_CS_N<0>")
	)
	(segment
		(start 48.889666 -246.384572)
		(end 48.889666 -246.84482)
		(width 0.18288)
		(layer "In2.Cu")
		(net "M_B_CPU1_SB_CS_N<0>")
	)
	(segment
		(start 44.038774 -245.936516)
		(end 43.765978 -246.209312)
		(width 0.18288)
		(layer "In2.Cu")
		(net "M_B_CPU1_SB_CS_N<0>")
	)
	(segment
		(start 49.082706 -246.191532)
		(end 48.889666 -246.384572)
		(width 0.18288)
		(layer "In2.Cu")
		(net "M_B_CPU1_SB_CS_N<0>")
	)
	(segment
		(start 73.29805 -246.739918)
		(end 71.593964 -246.739918)
		(width 0.18288)
		(layer "In2.Cu")
		(net "M_B_CPU1_SB_CS_N<0>")
	)
	(segment
		(start 42.60469 -245.383812)
		(end 42.152316 -245.383812)
		(width 0.18288)
		(layer "In2.Cu")
		(net "M_B_CPU1_SB_CS_N<0>")
	)
	(segment
		(start 43.008042 -246.209312)
		(end 42.79773 -245.999)
		(width 0.18288)
		(layer "In2.Cu")
		(net "M_B_CPU1_SB_CS_N<0>")
	)
	(segment
		(start 63.75908 -246.24411)
		(end 63.384684 -245.869714)
		(width 0.18288)
		(layer "In2.Cu")
		(net "M_B_CPU1_SB_CS_N<0>")
	)
	(segment
		(start 58.465974 -246.312944)
		(end 58.0771 -245.92407)
		(width 0.18288)
		(layer "In2.Cu")
		(net "M_B_CPU1_SB_CS_N<0>")
	)
	(segment
		(start 60.043568 -246.171212)
		(end 59.39663 -246.171212)
		(width 0.18288)
		(layer "In2.Cu")
		(net "M_B_CPU1_SB_CS_N<0>")
	)
	(segment
		(start 52.515262 -246.140986)
		(end 52.347368 -245.973092)
		(width 0.18288)
		(layer "In2.Cu")
		(net "M_B_CPU1_SB_CS_N<0>")
	)
	(segment
		(start 47.65802 -246.384572)
		(end 47.46498 -246.191532)
		(width 0.18288)
		(layer "In2.Cu")
		(net "M_B_CPU1_SB_CS_N<0>")
	)
	(segment
		(start 40.27551 -245.97106)
		(end 40.07104 -245.76659)
		(width 0.18288)
		(layer "In2.Cu")
		(net "M_B_CPU1_SB_CS_N<0>")
	)
	(segment
		(start 71.593964 -246.739918)
		(end 70.70598 -245.851934)
		(width 0.18288)
		(layer "In2.Cu")
		(net "M_B_CPU1_SB_CS_N<0>")
	)
	(segment
		(start 64.529208 -245.851172)
		(end 64.13627 -246.24411)
		(width 0.18288)
		(layer "In2.Cu")
		(net "M_B_CPU1_SB_CS_N<0>")
	)
	(segment
		(start 41.959276 -245.999)
		(end 41.766236 -246.19204)
		(width 0.18288)
		(layer "In2.Cu")
		(net "M_B_CPU1_SB_CS_N<0>")
	)
	(segment
		(start 41.36644 -246.86133)
		(end 41.180258 -247.047512)
		(width 0.18288)
		(layer "In2.Cu")
		(net "M_B_CPU1_SB_CS_N<0>")
	)
	(segment
		(start 41.36644 -246.35206)
		(end 41.36644 -246.86133)
		(width 0.18288)
		(layer "In2.Cu")
		(net "M_B_CPU1_SB_CS_N<0>")
	)
	(segment
		(start 54.93766 -246.140986)
		(end 52.515262 -246.140986)
		(width 0.18288)
		(layer "In2.Cu")
		(net "M_B_CPU1_SB_CS_N<0>")
	)
	(segment
		(start 56.6293 -246.202708)
		(end 56.20131 -246.202708)
		(width 0.18288)
		(layer "In2.Cu")
		(net "M_B_CPU1_SB_CS_N<0>")
	)
	(segment
		(start 40.468804 -247.047512)
		(end 40.27551 -246.854218)
		(width 0.18288)
		(layer "In2.Cu")
		(net "M_B_CPU1_SB_CS_N<0>")
	)
	(segment
		(start 55.39867 -245.679976)
		(end 54.93766 -246.140986)
		(width 0.18288)
		(layer "In2.Cu")
		(net "M_B_CPU1_SB_CS_N<0>")
	)
	(segment
		(start 45.065696 -246.191532)
		(end 44.81068 -245.936516)
		(width 0.18288)
		(layer "In2.Cu")
		(net "M_B_CPU1_SB_CS_N<0>")
	)
	(segment
		(start 87.89162 -246.057166)
		(end 87.862664 -246.040148)
		(width 0.088646)
		(layer "In2.Cu")
		(net "M_B_CPU1_SB_CS_N<0>")
	)
	(segment
		(start 61.441838 -246.515382)
		(end 60.387738 -246.515382)
		(width 0.18288)
		(layer "In2.Cu")
		(net "M_B_CPU1_SB_CS_N<0>")
	)
	(segment
		(start 83.520534 -246.219726)
		(end 83.14055 -246.219726)
		(width 0.088646)
		(layer "In2.Cu")
		(net "M_B_CPU1_SB_CS_N<0>")
	)
	(segment
		(start 44.81068 -245.936516)
		(end 44.038774 -245.936516)
		(width 0.18288)
		(layer "In2.Cu")
		(net "M_B_CPU1_SB_CS_N<0>")
	)
	(segment
		(start 51.480974 -245.973092)
		(end 51.262534 -246.191532)
		(width 0.18288)
		(layer "In2.Cu")
		(net "M_B_CPU1_SB_CS_N<0>")
	)
	(segment
		(start 62.087506 -245.869714)
		(end 61.441838 -246.515382)
		(width 0.18288)
		(layer "In2.Cu")
		(net "M_B_CPU1_SB_CS_N<0>")
	)
	(segment
		(start 47.65802 -246.84482)
		(end 47.65802 -246.384572)
		(width 0.18288)
		(layer "In2.Cu")
		(net "M_B_CPU1_SB_CS_N<0>")
	)
	(segment
		(start 48.696626 -247.03786)
		(end 47.85106 -247.03786)
		(width 0.18288)
		(layer "In2.Cu")
		(net "M_B_CPU1_SB_CS_N<0>")
	)
	(segment
		(start 48.889666 -246.84482)
		(end 48.696626 -247.03786)
		(width 0.18288)
		(layer "In2.Cu")
		(net "M_B_CPU1_SB_CS_N<0>")
	)
	(segment
		(start 63.384684 -245.869714)
		(end 62.087506 -245.869714)
		(width 0.18288)
		(layer "In2.Cu")
		(net "M_B_CPU1_SB_CS_N<0>")
	)
	(arc
		(start 85.983064 -246.040148)
		(mid 85.795866 -245.990005)
		(end 85.608668 -246.040148)
		(width 0.088646)
		(layer "In2.Cu")
		(net "M_B_CPU1_SB_CS_N<0>")
	)
	(arc
		(start 87.862664 -246.040148)
		(mid 87.675466 -245.990005)
		(end 87.488268 -246.040148)
		(width 0.088646)
		(layer "In2.Cu")
		(net "M_B_CPU1_SB_CS_N<0>")
	)
	(arc
		(start 84.103464 -246.040148)
		(mid 84.013192 -246.002549)
		(end 83.916266 -245.989602)
		(width 0.088646)
		(layer "In2.Cu")
		(net "M_B_CPU1_SB_CS_N<0>")
	)
	(arc
		(start 87.488268 -246.040148)
		(mid 87.205566 -246.115924)
		(end 86.922864 -246.040148)
		(width 0.088646)
		(layer "In2.Cu")
		(net "M_B_CPU1_SB_CS_N<0>")
	)
	(arc
		(start 86.922864 -246.040148)
		(mid 86.735666 -245.990005)
		(end 86.548468 -246.040148)
		(width 0.088646)
		(layer "In2.Cu")
		(net "M_B_CPU1_SB_CS_N<0>")
	)
	(arc
		(start 85.043264 -246.040148)
		(mid 84.856066 -245.990005)
		(end 84.668868 -246.040148)
		(width 0.088646)
		(layer "In2.Cu")
		(net "M_B_CPU1_SB_CS_N<0>")
	)
	(arc
		(start 86.548468 -246.040148)
		(mid 86.265766 -246.115924)
		(end 85.983064 -246.040148)
		(width 0.088646)
		(layer "In2.Cu")
		(net "M_B_CPU1_SB_CS_N<0>")
	)
	(arc
		(start 84.668868 -246.040148)
		(mid 84.386166 -246.115924)
		(end 84.103464 -246.040148)
		(width 0.088646)
		(layer "In2.Cu")
		(net "M_B_CPU1_SB_CS_N<0>")
	)
	(arc
		(start 85.608668 -246.040148)
		(mid 85.325966 -246.115924)
		(end 85.043264 -246.040148)
		(width 0.088646)
		(layer "In2.Cu")
		(net "M_B_CPU1_SB_CS_N<0>")
	)
	(segment
		(start 90.494612 -243.644674)
		(end 90.494612 -243.108988)
		(width 0.20066)
		(layer "F.Cu")
		(net "M_B_CPU1_SB_CB<7>")
	)
	(segment
		(start 47.753778 -239.2426)
		(end 47.60468 -239.391698)
		(width 0.20066)
		(layer "F.Cu")
		(net "M_B_CPU1_SB_CB<7>")
	)
	(segment
		(start 44.38142 -239.405922)
		(end 44.238926 -239.263428)
		(width 0.20066)
		(layer "F.Cu")
		(net "M_B_CPU1_SB_CB<7>")
	)
	(segment
		(start 47.60468 -239.391698)
		(end 47.060358 -239.391698)
		(width 0.20066)
		(layer "F.Cu")
		(net "M_B_CPU1_SB_CB<7>")
	)
	(segment
		(start 47.882302 -238.962438)
		(end 47.753778 -239.090962)
		(width 0.20066)
		(layer "F.Cu")
		(net "M_B_CPU1_SB_CB<7>")
	)
	(segment
		(start 51.064414 -238.966756)
		(end 49.959514 -238.966756)
		(width 0.20066)
		(layer "F.Cu")
		(net "M_B_CPU1_SB_CB<7>")
	)
	(segment
		(start 44.238926 -239.09274)
		(end 44.112942 -238.966756)
		(width 0.20066)
		(layer "F.Cu")
		(net "M_B_CPU1_SB_CB<7>")
	)
	(segment
		(start 48.935894 -239.174274)
		(end 48.489362 -239.174274)
		(width 0.20066)
		(layer "F.Cu")
		(net "M_B_CPU1_SB_CB<7>")
	)
	(segment
		(start 49.959514 -238.966756)
		(end 49.143412 -238.966756)
		(width 0.20066)
		(layer "F.Cu")
		(net "M_B_CPU1_SB_CB<7>")
	)
	(segment
		(start 44.112942 -238.966756)
		(end 42.415714 -238.966756)
		(width 0.20066)
		(layer "F.Cu")
		(net "M_B_CPU1_SB_CB<7>")
	)
	(segment
		(start 47.753778 -239.090962)
		(end 47.753778 -239.2426)
		(width 0.20066)
		(layer "F.Cu")
		(net "M_B_CPU1_SB_CB<7>")
	)
	(segment
		(start 44.987464 -239.391698)
		(end 44.749466 -239.391698)
		(width 0.101854)
		(layer "F.Cu")
		(net "M_B_CPU1_SB_CB<7>")
	)
	(segment
		(start 90.494866 -243.644928)
		(end 90.494612 -243.644674)
		(width 0.20066)
		(layer "F.Cu")
		(net "M_B_CPU1_SB_CB<7>")
	)
	(segment
		(start 47.060358 -239.391698)
		(end 44.987464 -239.391698)
		(width 0.1016)
		(layer "F.Cu")
		(net "M_B_CPU1_SB_CB<7>")
	)
	(segment
		(start 44.735242 -239.405922)
		(end 44.38142 -239.405922)
		(width 0.20066)
		(layer "F.Cu")
		(net "M_B_CPU1_SB_CB<7>")
	)
	(segment
		(start 48.489362 -239.174274)
		(end 48.277526 -238.962438)
		(width 0.20066)
		(layer "F.Cu")
		(net "M_B_CPU1_SB_CB<7>")
	)
	(segment
		(start 44.749466 -239.391698)
		(end 44.735242 -239.405922)
		(width 0.101854)
		(layer "F.Cu")
		(net "M_B_CPU1_SB_CB<7>")
	)
	(segment
		(start 48.277526 -238.962438)
		(end 47.882302 -238.962438)
		(width 0.20066)
		(layer "F.Cu")
		(net "M_B_CPU1_SB_CB<7>")
	)
	(segment
		(start 44.238926 -239.263428)
		(end 44.238926 -239.09274)
		(width 0.20066)
		(layer "F.Cu")
		(net "M_B_CPU1_SB_CB<7>")
	)
	(segment
		(start 49.143412 -238.966756)
		(end 48.935894 -239.174274)
		(width 0.20066)
		(layer "F.Cu")
		(net "M_B_CPU1_SB_CB<7>")
	)
	(segment
		(start 63.47079 -239.095788)
		(end 63.27775 -239.288828)
		(width 0.18288)
		(layer "In2.Cu")
		(net "M_B_CPU1_SB_CB<7>")
	)
	(segment
		(start 69.775578 -241.61369)
		(end 69.582538 -241.42065)
		(width 0.18288)
		(layer "In2.Cu")
		(net "M_B_CPU1_SB_CB<7>")
	)
	(segment
		(start 89.932764 -243.54282)
		(end 89.93124 -243.543582)
		(width 0.088646)
		(layer "In2.Cu")
		(net "M_B_CPU1_SB_CB<7>")
	)
	(segment
		(start 67.01663 -239.794034)
		(end 67.120008 -239.54486)
		(width 0.18288)
		(layer "In2.Cu")
		(net "M_B_CPU1_SB_CB<7>")
	)
	(segment
		(start 61.994288 -239.98809)
		(end 61.583824 -240.398554)
		(width 0.18288)
		(layer "In2.Cu")
		(net "M_B_CPU1_SB_CB<7>")
	)
	(segment
		(start 68.618354 -239.99063)
		(end 68.618354 -239.776)
		(width 0.18288)
		(layer "In2.Cu")
		(net "M_B_CPU1_SB_CB<7>")
	)
	(segment
		(start 63.92037 -239.095788)
		(end 63.47079 -239.095788)
		(width 0.18288)
		(layer "In2.Cu")
		(net "M_B_CPU1_SB_CB<7>")
	)
	(segment
		(start 83.884262 -243.68252)
		(end 83.638898 -243.68252)
		(width 0.088646)
		(layer "In2.Cu")
		(net "M_B_CPU1_SB_CB<7>")
	)
	(segment
		(start 63.08471 -240.171732)
		(end 62.848998 -240.171732)
		(width 0.18288)
		(layer "In2.Cu")
		(net "M_B_CPU1_SB_CB<7>")
	)
	(segment
		(start 51.549554 -238.966756)
		(end 51.064414 -238.966756)
		(width 0.18288)
		(layer "In2.Cu")
		(net "M_B_CPU1_SB_CB<7>")
	)
	(segment
		(start 71.03872 -241.42065)
		(end 71.03872 -240.78184)
		(width 0.18288)
		(layer "In2.Cu")
		(net "M_B_CPU1_SB_CB<7>")
	)
	(segment
		(start 70.13956 -241.61369)
		(end 69.775578 -241.61369)
		(width 0.18288)
		(layer "In2.Cu")
		(net "M_B_CPU1_SB_CB<7>")
	)
	(segment
		(start 62.665356 -239.98809)
		(end 61.994288 -239.98809)
		(width 0.18288)
		(layer "In2.Cu")
		(net "M_B_CPU1_SB_CB<7>")
	)
	(segment
		(start 68.813172 -240.185448)
		(end 68.618354 -239.99063)
		(width 0.18288)
		(layer "In2.Cu")
		(net "M_B_CPU1_SB_CB<7>")
	)
	(segment
		(start 83.493864 -243.537486)
		(end 83.064096 -243.537486)
		(width 0.088646)
		(layer "In2.Cu")
		(net "M_B_CPU1_SB_CB<7>")
	)
	(segment
		(start 71.03872 -240.78184)
		(end 70.84568 -240.5888)
		(width 0.18288)
		(layer "In2.Cu")
		(net "M_B_CPU1_SB_CB<7>")
	)
	(segment
		(start 67.681348 -240.088928)
		(end 67.428872 -240.193576)
		(width 0.18288)
		(layer "In2.Cu")
		(net "M_B_CPU1_SB_CB<7>")
	)
	(segment
		(start 54.506368 -238.253524)
		(end 53.982366 -238.777526)
		(width 0.18288)
		(layer "In2.Cu")
		(net "M_B_CPU1_SB_CB<7>")
	)
	(segment
		(start 60.278264 -240.398554)
		(end 59.838082 -239.958372)
		(width 0.18288)
		(layer "In2.Cu")
		(net "M_B_CPU1_SB_CB<7>")
	)
	(segment
		(start 59.293252 -239.958372)
		(end 58.735468 -239.400588)
		(width 0.18288)
		(layer "In2.Cu")
		(net "M_B_CPU1_SB_CB<7>")
	)
	(segment
		(start 69.582538 -240.378488)
		(end 69.389498 -240.185448)
		(width 0.18288)
		(layer "In2.Cu")
		(net "M_B_CPU1_SB_CB<7>")
	)
	(segment
		(start 67.881754 -239.60328)
		(end 67.681348 -240.088928)
		(width 0.18288)
		(layer "In2.Cu")
		(net "M_B_CPU1_SB_CB<7>")
	)
	(segment
		(start 67.428872 -240.193576)
		(end 67.130676 -240.069878)
		(width 0.18288)
		(layer "In2.Cu")
		(net "M_B_CPU1_SB_CB<7>")
	)
	(segment
		(start 67.120008 -239.54486)
		(end 67.06743 -239.276382)
		(width 0.18288)
		(layer "In2.Cu")
		(net "M_B_CPU1_SB_CB<7>")
	)
	(segment
		(start 55.814214 -239.120172)
		(end 54.947566 -238.253524)
		(width 0.18288)
		(layer "In2.Cu")
		(net "M_B_CPU1_SB_CB<7>")
	)
	(segment
		(start 69.389498 -240.185448)
		(end 68.813172 -240.185448)
		(width 0.18288)
		(layer "In2.Cu")
		(net "M_B_CPU1_SB_CB<7>")
	)
	(segment
		(start 83.064096 -243.537486)
		(end 73.907142 -243.537486)
		(width 0.18288)
		(layer "In2.Cu")
		(net "M_B_CPU1_SB_CB<7>")
	)
	(segment
		(start 70.84568 -240.5888)
		(end 70.52564 -240.5888)
		(width 0.18288)
		(layer "In2.Cu")
		(net "M_B_CPU1_SB_CB<7>")
	)
	(segment
		(start 69.582538 -241.42065)
		(end 69.582538 -240.378488)
		(width 0.18288)
		(layer "In2.Cu")
		(net "M_B_CPU1_SB_CB<7>")
	)
	(segment
		(start 62.848998 -240.171732)
		(end 62.665356 -239.98809)
		(width 0.18288)
		(layer "In2.Cu")
		(net "M_B_CPU1_SB_CB<7>")
	)
	(segment
		(start 68.13423 -239.498632)
		(end 67.881754 -239.60328)
		(width 0.18288)
		(layer "In2.Cu")
		(net "M_B_CPU1_SB_CB<7>")
	)
	(segment
		(start 84.198714 -243.598446)
		(end 84.183982 -243.607082)
		(width 0.088646)
		(layer "In2.Cu")
		(net "M_B_CPU1_SB_CB<7>")
	)
	(segment
		(start 52.115466 -238.400844)
		(end 51.549554 -238.966756)
		(width 0.18288)
		(layer "In2.Cu")
		(net "M_B_CPU1_SB_CB<7>")
	)
	(segment
		(start 52.420266 -238.400844)
		(end 52.115466 -238.400844)
		(width 0.18288)
		(layer "In2.Cu")
		(net "M_B_CPU1_SB_CB<7>")
	)
	(segment
		(start 68.618354 -239.776)
		(end 68.547234 -239.669574)
		(width 0.18288)
		(layer "In2.Cu")
		(net "M_B_CPU1_SB_CB<7>")
	)
	(segment
		(start 54.947566 -238.253524)
		(end 54.506368 -238.253524)
		(width 0.18288)
		(layer "In2.Cu")
		(net "M_B_CPU1_SB_CB<7>")
	)
	(segment
		(start 89.272364 -243.597684)
		(end 89.272364 -243.59743)
		(width 0.088646)
		(layer "In2.Cu")
		(net "M_B_CPU1_SB_CB<7>")
	)
	(segment
		(start 85.513164 -243.598446)
		(end 85.51291 -243.598446)
		(width 0.088646)
		(layer "In2.Cu")
		(net "M_B_CPU1_SB_CB<7>")
	)
	(segment
		(start 58.426096 -239.400588)
		(end 58.184288 -239.642396)
		(width 0.18288)
		(layer "In2.Cu")
		(net "M_B_CPU1_SB_CB<7>")
	)
	(segment
		(start 61.583824 -240.398554)
		(end 60.278264 -240.398554)
		(width 0.18288)
		(layer "In2.Cu")
		(net "M_B_CPU1_SB_CB<7>")
	)
	(segment
		(start 65.808352 -239.49279)
		(end 64.317372 -239.49279)
		(width 0.18288)
		(layer "In2.Cu")
		(net "M_B_CPU1_SB_CB<7>")
	)
	(segment
		(start 88.332564 -243.598446)
		(end 88.33231 -243.598446)
		(width 0.088646)
		(layer "In2.Cu")
		(net "M_B_CPU1_SB_CB<7>")
	)
	(segment
		(start 85.138514 -243.598446)
		(end 85.123782 -243.607082)
		(width 0.088646)
		(layer "In2.Cu")
		(net "M_B_CPU1_SB_CB<7>")
	)
	(segment
		(start 58.184288 -239.642396)
		(end 56.955182 -239.642396)
		(width 0.18288)
		(layer "In2.Cu")
		(net "M_B_CPU1_SB_CB<7>")
	)
	(segment
		(start 89.929716 -243.544598)
		(end 89.84107 -243.596414)
		(width 0.088646)
		(layer "In2.Cu")
		(net "M_B_CPU1_SB_CB<7>")
	)
	(segment
		(start 70.3326 -240.78184)
		(end 70.3326 -241.42065)
		(width 0.18288)
		(layer "In2.Cu")
		(net "M_B_CPU1_SB_CB<7>")
	)
	(segment
		(start 64.317372 -239.49279)
		(end 63.92037 -239.095788)
		(width 0.18288)
		(layer "In2.Cu")
		(net "M_B_CPU1_SB_CB<7>")
	)
	(segment
		(start 71.23176 -241.61369)
		(end 71.03872 -241.42065)
		(width 0.18288)
		(layer "In2.Cu")
		(net "M_B_CPU1_SB_CB<7>")
	)
	(segment
		(start 59.838082 -239.958372)
		(end 59.293252 -239.958372)
		(width 0.18288)
		(layer "In2.Cu")
		(net "M_B_CPU1_SB_CB<7>")
	)
	(segment
		(start 70.52564 -240.5888)
		(end 70.3326 -240.78184)
		(width 0.18288)
		(layer "In2.Cu")
		(net "M_B_CPU1_SB_CB<7>")
	)
	(segment
		(start 83.638898 -243.68252)
		(end 83.493864 -243.537486)
		(width 0.088646)
		(layer "In2.Cu")
		(net "M_B_CPU1_SB_CB<7>")
	)
	(segment
		(start 68.547234 -239.669574)
		(end 68.13423 -239.498632)
		(width 0.18288)
		(layer "In2.Cu")
		(net "M_B_CPU1_SB_CB<7>")
	)
	(segment
		(start 53.982366 -238.777526)
		(end 52.796948 -238.777526)
		(width 0.18288)
		(layer "In2.Cu")
		(net "M_B_CPU1_SB_CB<7>")
	)
	(segment
		(start 56.432958 -239.120172)
		(end 55.814214 -239.120172)
		(width 0.18288)
		(layer "In2.Cu")
		(net "M_B_CPU1_SB_CB<7>")
	)
	(segment
		(start 71.983346 -241.61369)
		(end 71.23176 -241.61369)
		(width 0.18288)
		(layer "In2.Cu")
		(net "M_B_CPU1_SB_CB<7>")
	)
	(segment
		(start 66.202814 -239.098328)
		(end 65.808352 -239.49279)
		(width 0.18288)
		(layer "In2.Cu")
		(net "M_B_CPU1_SB_CB<7>")
	)
	(segment
		(start 70.3326 -241.42065)
		(end 70.13956 -241.61369)
		(width 0.18288)
		(layer "In2.Cu")
		(net "M_B_CPU1_SB_CB<7>")
	)
	(segment
		(start 58.735468 -239.400588)
		(end 58.426096 -239.400588)
		(width 0.18288)
		(layer "In2.Cu")
		(net "M_B_CPU1_SB_CB<7>")
	)
	(segment
		(start 67.130676 -240.069878)
		(end 67.01663 -239.794034)
		(width 0.18288)
		(layer "In2.Cu")
		(net "M_B_CPU1_SB_CB<7>")
	)
	(segment
		(start 88.896444 -243.599208)
		(end 88.8873 -243.604542)
		(width 0.088646)
		(layer "In2.Cu")
		(net "M_B_CPU1_SB_CB<7>")
	)
	(segment
		(start 63.27775 -239.288828)
		(end 63.27775 -239.978692)
		(width 0.18288)
		(layer "In2.Cu")
		(net "M_B_CPU1_SB_CB<7>")
	)
	(segment
		(start 66.850768 -239.098328)
		(end 66.202814 -239.098328)
		(width 0.18288)
		(layer "In2.Cu")
		(net "M_B_CPU1_SB_CB<7>")
	)
	(segment
		(start 73.907142 -243.537486)
		(end 71.983346 -241.61369)
		(width 0.18288)
		(layer "In2.Cu")
		(net "M_B_CPU1_SB_CB<7>")
	)
	(segment
		(start 63.27775 -239.978692)
		(end 63.08471 -240.171732)
		(width 0.18288)
		(layer "In2.Cu")
		(net "M_B_CPU1_SB_CB<7>")
	)
	(segment
		(start 56.955182 -239.642396)
		(end 56.432958 -239.120172)
		(width 0.18288)
		(layer "In2.Cu")
		(net "M_B_CPU1_SB_CB<7>")
	)
	(segment
		(start 67.06743 -239.276382)
		(end 66.850768 -239.098328)
		(width 0.18288)
		(layer "In2.Cu")
		(net "M_B_CPU1_SB_CB<7>")
	)
	(segment
		(start 52.796948 -238.777526)
		(end 52.420266 -238.400844)
		(width 0.18288)
		(layer "In2.Cu")
		(net "M_B_CPU1_SB_CB<7>")
	)
	(arc
		(start 87.958168 -243.598446)
		(mid 87.675466 -243.674222)
		(end 87.392764 -243.598446)
		(width 0.088646)
		(layer "In2.Cu")
		(net "M_B_CPU1_SB_CB<7>")
	)
	(arc
		(start 88.33231 -243.598446)
		(mid 88.145256 -243.548396)
		(end 87.958168 -243.598446)
		(width 0.088646)
		(layer "In2.Cu")
		(net "M_B_CPU1_SB_CB<7>")
	)
	(arc
		(start 85.51291 -243.598446)
		(mid 85.325712 -243.548303)
		(end 85.138514 -243.598446)
		(width 0.088646)
		(layer "In2.Cu")
		(net "M_B_CPU1_SB_CB<7>")
	)
	(arc
		(start 87.018368 -243.598446)
		(mid 86.735666 -243.674222)
		(end 86.452964 -243.598446)
		(width 0.088646)
		(layer "In2.Cu")
		(net "M_B_CPU1_SB_CB<7>")
	)
	(arc
		(start 89.84107 -243.596414)
		(mid 89.556881 -243.673764)
		(end 89.272364 -243.597684)
		(width 0.088646)
		(layer "In2.Cu")
		(net "M_B_CPU1_SB_CB<7>")
	)
	(arc
		(start 88.8873 -243.604542)
		(mid 88.609122 -243.674265)
		(end 88.332564 -243.598446)
		(width 0.088646)
		(layer "In2.Cu")
		(net "M_B_CPU1_SB_CB<7>")
	)
	(arc
		(start 90.494612 -243.108988)
		(mid 90.227581 -243.343896)
		(end 89.932764 -243.54282)
		(width 0.088646)
		(layer "In2.Cu")
		(net "M_B_CPU1_SB_CB<7>")
	)
	(arc
		(start 87.392764 -243.598446)
		(mid 87.205566 -243.548303)
		(end 87.018368 -243.598446)
		(width 0.088646)
		(layer "In2.Cu")
		(net "M_B_CPU1_SB_CB<7>")
	)
	(arc
		(start 84.183982 -243.607082)
		(mid 84.038791 -243.66334)
		(end 83.884262 -243.68252)
		(width 0.088646)
		(layer "In2.Cu")
		(net "M_B_CPU1_SB_CB<7>")
	)
	(arc
		(start 84.57311 -243.598446)
		(mid 84.385912 -243.548303)
		(end 84.198714 -243.598446)
		(width 0.088646)
		(layer "In2.Cu")
		(net "M_B_CPU1_SB_CB<7>")
	)
	(arc
		(start 85.123782 -243.607082)
		(mid 84.847307 -243.674402)
		(end 84.57311 -243.598446)
		(width 0.088646)
		(layer "In2.Cu")
		(net "M_B_CPU1_SB_CB<7>")
	)
	(arc
		(start 86.452964 -243.598446)
		(mid 86.265766 -243.548303)
		(end 86.078568 -243.598446)
		(width 0.088646)
		(layer "In2.Cu")
		(net "M_B_CPU1_SB_CB<7>")
	)
	(arc
		(start 89.272364 -243.59743)
		(mid 89.084164 -243.547772)
		(end 88.896444 -243.599208)
		(width 0.088646)
		(layer "In2.Cu")
		(net "M_B_CPU1_SB_CB<7>")
	)
	(arc
		(start 86.078568 -243.598446)
		(mid 85.795866 -243.674222)
		(end 85.513164 -243.598446)
		(width 0.088646)
		(layer "In2.Cu")
		(net "M_B_CPU1_SB_CB<7>")
	)
	(arc
		(start 89.93124 -243.543582)
		(mid 89.930475 -243.544086)
		(end 89.929716 -243.544598)
		(width 0.088646)
		(layer "In2.Cu")
		(net "M_B_CPU1_SB_CB<7>")
	)
	(segment
		(start 43.562778 -240.666778)
		(end 42.415714 -240.666778)
		(width 0.20066)
		(layer "F.Cu")
		(net "M_B_CPU1_SB_CB<6>")
	)
	(segment
		(start 47.693326 -240.241836)
		(end 47.060358 -240.241836)
		(width 0.20066)
		(layer "F.Cu")
		(net "M_B_CPU1_SB_CB<6>")
	)
	(segment
		(start 43.99788 -240.231676)
		(end 43.562778 -240.666778)
		(width 0.20066)
		(layer "F.Cu")
		(net "M_B_CPU1_SB_CB<6>")
	)
	(segment
		(start 45.000418 -240.241836)
		(end 44.745402 -240.241836)
		(width 0.101854)
		(layer "F.Cu")
		(net "M_B_CPU1_SB_CB<6>")
	)
	(segment
		(start 47.83709 -240.3856)
		(end 47.693326 -240.241836)
		(width 0.20066)
		(layer "F.Cu")
		(net "M_B_CPU1_SB_CB<6>")
	)
	(segment
		(start 90.024712 -244.458744)
		(end 90.024966 -244.45849)
		(width 0.20066)
		(layer "F.Cu")
		(net "M_B_CPU1_SB_CB<6>")
	)
	(segment
		(start 47.060358 -240.241836)
		(end 45.000418 -240.241836)
		(width 0.1016)
		(layer "F.Cu")
		(net "M_B_CPU1_SB_CB<6>")
	)
	(segment
		(start 47.83709 -240.711228)
		(end 47.83709 -240.3856)
		(width 0.20066)
		(layer "F.Cu")
		(net "M_B_CPU1_SB_CB<6>")
	)
	(segment
		(start 48.432974 -240.878614)
		(end 48.004476 -240.878614)
		(width 0.20066)
		(layer "F.Cu")
		(net "M_B_CPU1_SB_CB<6>")
	)
	(segment
		(start 48.004476 -240.878614)
		(end 47.83709 -240.711228)
		(width 0.20066)
		(layer "F.Cu")
		(net "M_B_CPU1_SB_CB<6>")
	)
	(segment
		(start 48.64481 -240.666778)
		(end 48.432974 -240.878614)
		(width 0.20066)
		(layer "F.Cu")
		(net "M_B_CPU1_SB_CB<6>")
	)
	(segment
		(start 51.064414 -240.666778)
		(end 49.959514 -240.666778)
		(width 0.20066)
		(layer "F.Cu")
		(net "M_B_CPU1_SB_CB<6>")
	)
	(segment
		(start 44.735242 -240.231676)
		(end 43.99788 -240.231676)
		(width 0.20066)
		(layer "F.Cu")
		(net "M_B_CPU1_SB_CB<6>")
	)
	(segment
		(start 90.024966 -244.45849)
		(end 90.024966 -243.922804)
		(width 0.20066)
		(layer "F.Cu")
		(net "M_B_CPU1_SB_CB<6>")
	)
	(segment
		(start 49.959514 -240.666778)
		(end 48.64481 -240.666778)
		(width 0.20066)
		(layer "F.Cu")
		(net "M_B_CPU1_SB_CB<6>")
	)
	(segment
		(start 44.745402 -240.241836)
		(end 44.735242 -240.231676)
		(width 0.101854)
		(layer "F.Cu")
		(net "M_B_CPU1_SB_CB<6>")
	)
	(segment
		(start 58.40476 -241.079528)
		(end 58.255916 -241.228372)
		(width 0.18288)
		(layer "In2.Cu")
		(net "M_B_CPU1_SB_CB<6>")
	)
	(segment
		(start 66.572892 -242.645438)
		(end 66.19367 -242.645438)
		(width 0.18288)
		(layer "In2.Cu")
		(net "M_B_CPU1_SB_CB<6>")
	)
	(segment
		(start 55.234586 -240.775998)
		(end 55.234586 -240.460022)
		(width 0.18288)
		(layer "In2.Cu")
		(net "M_B_CPU1_SB_CB<6>")
	)
	(segment
		(start 51.654964 -240.666778)
		(end 51.064414 -240.666778)
		(width 0.18288)
		(layer "In2.Cu")
		(net "M_B_CPU1_SB_CB<6>")
	)
	(segment
		(start 62.853316 -241.97945)
		(end 62.561978 -241.97945)
		(width 0.18288)
		(layer "In2.Cu")
		(net "M_B_CPU1_SB_CB<6>")
	)
	(segment
		(start 53.69814 -240.392966)
		(end 53.69814 -240.89487)
		(width 0.18288)
		(layer "In2.Cu")
		(net "M_B_CPU1_SB_CB<6>")
	)
	(segment
		(start 66.765932 -241.426238)
		(end 66.765932 -242.452398)
		(width 0.18288)
		(layer "In2.Cu")
		(net "M_B_CPU1_SB_CB<6>")
	)
	(segment
		(start 86.548214 -244.412262)
		(end 86.533482 -244.420898)
		(width 0.088646)
		(layer "In2.Cu")
		(net "M_B_CPU1_SB_CB<6>")
	)
	(segment
		(start 66.765932 -242.452398)
		(end 66.572892 -242.645438)
		(width 0.18288)
		(layer "In2.Cu")
		(net "M_B_CPU1_SB_CB<6>")
	)
	(segment
		(start 61.684662 -242.023392)
		(end 60.245244 -242.023392)
		(width 0.18288)
		(layer "In2.Cu")
		(net "M_B_CPU1_SB_CB<6>")
	)
	(segment
		(start 52.13477 -240.186972)
		(end 51.654964 -240.666778)
		(width 0.18288)
		(layer "In2.Cu")
		(net "M_B_CPU1_SB_CB<6>")
	)
	(segment
		(start 83.45932 -244.228366)
		(end 83.064096 -244.228366)
		(width 0.088646)
		(layer "In2.Cu")
		(net "M_B_CPU1_SB_CB<6>")
	)
	(segment
		(start 59.924696 -241.702844)
		(end 59.500516 -241.702844)
		(width 0.18288)
		(layer "In2.Cu")
		(net "M_B_CPU1_SB_CB<6>")
	)
	(segment
		(start 73.12406 -244.228366)
		(end 71.541132 -242.645438)
		(width 0.18288)
		(layer "In2.Cu")
		(net "M_B_CPU1_SB_CB<6>")
	)
	(segment
		(start 58.8772 -241.079528)
		(end 58.40476 -241.079528)
		(width 0.18288)
		(layer "In2.Cu")
		(net "M_B_CPU1_SB_CB<6>")
	)
	(segment
		(start 62.561978 -241.97945)
		(end 62.282578 -241.70005)
		(width 0.18288)
		(layer "In2.Cu")
		(net "M_B_CPU1_SB_CB<6>")
	)
	(segment
		(start 53.69814 -240.89487)
		(end 53.53812 -241.05489)
		(width 0.18288)
		(layer "In2.Cu")
		(net "M_B_CPU1_SB_CB<6>")
	)
	(segment
		(start 67.665092 -241.939318)
		(end 68.341748 -241.939318)
		(width 0.18288)
		(layer "In2.Cu")
		(net "M_B_CPU1_SB_CB<6>")
	)
	(segment
		(start 60.245244 -242.023392)
		(end 59.924696 -241.702844)
		(width 0.18288)
		(layer "In2.Cu")
		(net "M_B_CPU1_SB_CB<6>")
	)
	(segment
		(start 67.472052 -242.452398)
		(end 67.472052 -242.132358)
		(width 0.18288)
		(layer "In2.Cu")
		(net "M_B_CPU1_SB_CB<6>")
	)
	(segment
		(start 62.008004 -241.70005)
		(end 61.684662 -242.023392)
		(width 0.18288)
		(layer "In2.Cu")
		(net "M_B_CPU1_SB_CB<6>")
	)
	(segment
		(start 52.68976 -240.186972)
		(end 52.13477 -240.186972)
		(width 0.18288)
		(layer "In2.Cu")
		(net "M_B_CPU1_SB_CB<6>")
	)
	(segment
		(start 52.856384 -240.353596)
		(end 52.68976 -240.186972)
		(width 0.18288)
		(layer "In2.Cu")
		(net "M_B_CPU1_SB_CB<6>")
	)
	(segment
		(start 68.534788 -241.426238)
		(end 68.341748 -241.233198)
		(width 0.18288)
		(layer "In2.Cu")
		(net "M_B_CPU1_SB_CB<6>")
	)
	(segment
		(start 67.472052 -242.132358)
		(end 67.665092 -241.939318)
		(width 0.18288)
		(layer "In2.Cu")
		(net "M_B_CPU1_SB_CB<6>")
	)
	(segment
		(start 66.00063 -242.452398)
		(end 66.00063 -241.985546)
		(width 0.18288)
		(layer "In2.Cu")
		(net "M_B_CPU1_SB_CB<6>")
	)
	(segment
		(start 68.534788 -241.746278)
		(end 68.534788 -241.426238)
		(width 0.18288)
		(layer "In2.Cu")
		(net "M_B_CPU1_SB_CB<6>")
	)
	(segment
		(start 68.341748 -241.939318)
		(end 68.534788 -241.746278)
		(width 0.18288)
		(layer "In2.Cu")
		(net "M_B_CPU1_SB_CB<6>")
	)
	(segment
		(start 63.756794 -241.075972)
		(end 62.853316 -241.97945)
		(width 0.18288)
		(layer "In2.Cu")
		(net "M_B_CPU1_SB_CB<6>")
	)
	(segment
		(start 53.016404 -241.05489)
		(end 52.856384 -240.89487)
		(width 0.18288)
		(layer "In2.Cu")
		(net "M_B_CPU1_SB_CB<6>")
	)
	(segment
		(start 85.608414 -244.412262)
		(end 85.593682 -244.420898)
		(width 0.088646)
		(layer "In2.Cu")
		(net "M_B_CPU1_SB_CB<6>")
	)
	(segment
		(start 83.871816 -244.350286)
		(end 83.58124 -244.350286)
		(width 0.088646)
		(layer "In2.Cu")
		(net "M_B_CPU1_SB_CB<6>")
	)
	(segment
		(start 66.958972 -241.233198)
		(end 66.765932 -241.426238)
		(width 0.18288)
		(layer "In2.Cu")
		(net "M_B_CPU1_SB_CB<6>")
	)
	(segment
		(start 58.255916 -241.228372)
		(end 56.738012 -241.228372)
		(width 0.18288)
		(layer "In2.Cu")
		(net "M_B_CPU1_SB_CB<6>")
	)
	(segment
		(start 66.00063 -241.985546)
		(end 65.091056 -241.075972)
		(width 0.18288)
		(layer "In2.Cu")
		(net "M_B_CPU1_SB_CB<6>")
	)
	(segment
		(start 88.427814 -244.412262)
		(end 88.413082 -244.420898)
		(width 0.088646)
		(layer "In2.Cu")
		(net "M_B_CPU1_SB_CB<6>")
	)
	(segment
		(start 65.091056 -241.075972)
		(end 63.756794 -241.075972)
		(width 0.18288)
		(layer "In2.Cu")
		(net "M_B_CPU1_SB_CB<6>")
	)
	(segment
		(start 59.500516 -241.702844)
		(end 58.8772 -241.079528)
		(width 0.18288)
		(layer "In2.Cu")
		(net "M_B_CPU1_SB_CB<6>")
	)
	(segment
		(start 56.738012 -241.228372)
		(end 56.478678 -240.969038)
		(width 0.18288)
		(layer "In2.Cu")
		(net "M_B_CPU1_SB_CB<6>")
	)
	(segment
		(start 83.58124 -244.350286)
		(end 83.45932 -244.228366)
		(width 0.088646)
		(layer "In2.Cu")
		(net "M_B_CPU1_SB_CB<6>")
	)
	(segment
		(start 53.85816 -240.232946)
		(end 53.69814 -240.392966)
		(width 0.18288)
		(layer "In2.Cu")
		(net "M_B_CPU1_SB_CB<6>")
	)
	(segment
		(start 55.234586 -240.460022)
		(end 55.00751 -240.232946)
		(width 0.18288)
		(layer "In2.Cu")
		(net "M_B_CPU1_SB_CB<6>")
	)
	(segment
		(start 62.282578 -241.70005)
		(end 62.008004 -241.70005)
		(width 0.18288)
		(layer "In2.Cu")
		(net "M_B_CPU1_SB_CB<6>")
	)
	(segment
		(start 56.478678 -240.969038)
		(end 55.427626 -240.969038)
		(width 0.18288)
		(layer "In2.Cu")
		(net "M_B_CPU1_SB_CB<6>")
	)
	(segment
		(start 84.668614 -244.412262)
		(end 84.653882 -244.420898)
		(width 0.088646)
		(layer "In2.Cu")
		(net "M_B_CPU1_SB_CB<6>")
	)
	(segment
		(start 55.00751 -240.232946)
		(end 53.85816 -240.232946)
		(width 0.18288)
		(layer "In2.Cu")
		(net "M_B_CPU1_SB_CB<6>")
	)
	(segment
		(start 71.541132 -242.645438)
		(end 67.665092 -242.645438)
		(width 0.18288)
		(layer "In2.Cu")
		(net "M_B_CPU1_SB_CB<6>")
	)
	(segment
		(start 67.665092 -242.645438)
		(end 67.472052 -242.452398)
		(width 0.18288)
		(layer "In2.Cu")
		(net "M_B_CPU1_SB_CB<6>")
	)
	(segment
		(start 55.427626 -240.969038)
		(end 55.234586 -240.775998)
		(width 0.18288)
		(layer "In2.Cu")
		(net "M_B_CPU1_SB_CB<6>")
	)
	(segment
		(start 53.53812 -241.05489)
		(end 53.016404 -241.05489)
		(width 0.18288)
		(layer "In2.Cu")
		(net "M_B_CPU1_SB_CB<6>")
	)
	(segment
		(start 52.856384 -240.89487)
		(end 52.856384 -240.353596)
		(width 0.18288)
		(layer "In2.Cu")
		(net "M_B_CPU1_SB_CB<6>")
	)
	(segment
		(start 87.488014 -244.412262)
		(end 87.473282 -244.420898)
		(width 0.088646)
		(layer "In2.Cu")
		(net "M_B_CPU1_SB_CB<6>")
	)
	(segment
		(start 68.341748 -241.233198)
		(end 66.958972 -241.233198)
		(width 0.18288)
		(layer "In2.Cu")
		(net "M_B_CPU1_SB_CB<6>")
	)
	(segment
		(start 83.064096 -244.228366)
		(end 73.12406 -244.228366)
		(width 0.18288)
		(layer "In2.Cu")
		(net "M_B_CPU1_SB_CB<6>")
	)
	(segment
		(start 66.19367 -242.645438)
		(end 66.00063 -242.452398)
		(width 0.18288)
		(layer "In2.Cu")
		(net "M_B_CPU1_SB_CB<6>")
	)
	(segment
		(start 89.46642 -244.35435)
		(end 89.352882 -244.420898)
		(width 0.088646)
		(layer "In2.Cu")
		(net "M_B_CPU1_SB_CB<6>")
	)
	(arc
		(start 87.473282 -244.420898)
		(mid 87.196807 -244.488218)
		(end 86.92261 -244.412262)
		(width 0.088646)
		(layer "In2.Cu")
		(net "M_B_CPU1_SB_CB<6>")
	)
	(arc
		(start 87.86241 -244.412262)
		(mid 87.675212 -244.362119)
		(end 87.488014 -244.412262)
		(width 0.088646)
		(layer "In2.Cu")
		(net "M_B_CPU1_SB_CB<6>")
	)
	(arc
		(start 84.653882 -244.420898)
		(mid 84.377407 -244.488218)
		(end 84.10321 -244.412262)
		(width 0.088646)
		(layer "In2.Cu")
		(net "M_B_CPU1_SB_CB<6>")
	)
	(arc
		(start 85.04301 -244.412262)
		(mid 84.855812 -244.362119)
		(end 84.668614 -244.412262)
		(width 0.088646)
		(layer "In2.Cu")
		(net "M_B_CPU1_SB_CB<6>")
	)
	(arc
		(start 89.352882 -244.420898)
		(mid 89.076407 -244.488218)
		(end 88.80221 -244.412262)
		(width 0.088646)
		(layer "In2.Cu")
		(net "M_B_CPU1_SB_CB<6>")
	)
	(arc
		(start 85.593682 -244.420898)
		(mid 85.317207 -244.488218)
		(end 85.04301 -244.412262)
		(width 0.088646)
		(layer "In2.Cu")
		(net "M_B_CPU1_SB_CB<6>")
	)
	(arc
		(start 84.10321 -244.412262)
		(mid 83.991594 -244.366032)
		(end 83.871816 -244.350286)
		(width 0.088646)
		(layer "In2.Cu")
		(net "M_B_CPU1_SB_CB<6>")
	)
	(arc
		(start 85.98281 -244.412262)
		(mid 85.795612 -244.362119)
		(end 85.608414 -244.412262)
		(width 0.088646)
		(layer "In2.Cu")
		(net "M_B_CPU1_SB_CB<6>")
	)
	(arc
		(start 88.413082 -244.420898)
		(mid 88.136607 -244.488218)
		(end 87.86241 -244.412262)
		(width 0.088646)
		(layer "In2.Cu")
		(net "M_B_CPU1_SB_CB<6>")
	)
	(arc
		(start 86.533482 -244.420898)
		(mid 86.257007 -244.488218)
		(end 85.98281 -244.412262)
		(width 0.088646)
		(layer "In2.Cu")
		(net "M_B_CPU1_SB_CB<6>")
	)
	(arc
		(start 90.024966 -243.922804)
		(mid 89.759475 -244.156415)
		(end 89.46642 -244.35435)
		(width 0.088646)
		(layer "In2.Cu")
		(net "M_B_CPU1_SB_CB<6>")
	)
	(arc
		(start 86.92261 -244.412262)
		(mid 86.735412 -244.362119)
		(end 86.548214 -244.412262)
		(width 0.088646)
		(layer "In2.Cu")
		(net "M_B_CPU1_SB_CB<6>")
	)
	(arc
		(start 88.80221 -244.412262)
		(mid 88.615012 -244.362119)
		(end 88.427814 -244.412262)
		(width 0.088646)
		(layer "In2.Cu")
		(net "M_B_CPU1_SB_CB<6>")
	)
	(segment
		(start 44.22013 -239.81664)
		(end 43.795188 -239.391698)
		(width 0.20066)
		(layer "F.Cu")
		(net "M_B_CPU1_SB_CB<5>")
	)
	(segment
		(start 39.649908 -239.81664)
		(end 38.315646 -239.81664)
		(width 0.20066)
		(layer "F.Cu")
		(net "M_B_CPU1_SB_CB<5>")
	)
	(segment
		(start 43.616626 -239.391698)
		(end 43.285918 -239.391698)
		(width 0.101854)
		(layer "F.Cu")
		(net "M_B_CPU1_SB_CB<5>")
	)
	(segment
		(start 43.285918 -239.391698)
		(end 41.3004 -239.391698)
		(width 0.1016)
		(layer "F.Cu")
		(net "M_B_CPU1_SB_CB<5>")
	)
	(segment
		(start 40.36568 -240.027968)
		(end 39.861236 -240.027968)
		(width 0.20066)
		(layer "F.Cu")
		(net "M_B_CPU1_SB_CB<5>")
	)
	(segment
		(start 40.520112 -239.545368)
		(end 40.520112 -239.873536)
		(width 0.20066)
		(layer "F.Cu")
		(net "M_B_CPU1_SB_CB<5>")
	)
	(segment
		(start 45.859446 -239.81664)
		(end 44.22013 -239.81664)
		(width 0.20066)
		(layer "F.Cu")
		(net "M_B_CPU1_SB_CB<5>")
	)
	(segment
		(start 46.964346 -239.81664)
		(end 45.859446 -239.81664)
		(width 0.20066)
		(layer "F.Cu")
		(net "M_B_CPU1_SB_CB<5>")
	)
	(segment
		(start 40.520112 -239.873536)
		(end 40.36568 -240.027968)
		(width 0.20066)
		(layer "F.Cu")
		(net "M_B_CPU1_SB_CB<5>")
	)
	(segment
		(start 41.29151 -239.382808)
		(end 40.682672 -239.382808)
		(width 0.20066)
		(layer "F.Cu")
		(net "M_B_CPU1_SB_CB<5>")
	)
	(segment
		(start 88.615012 -243.644674)
		(end 88.615012 -243.108988)
		(width 0.20066)
		(layer "F.Cu")
		(net "M_B_CPU1_SB_CB<5>")
	)
	(segment
		(start 39.861236 -240.027968)
		(end 39.649908 -239.81664)
		(width 0.20066)
		(layer "F.Cu")
		(net "M_B_CPU1_SB_CB<5>")
	)
	(segment
		(start 40.682672 -239.382808)
		(end 40.520112 -239.545368)
		(width 0.20066)
		(layer "F.Cu")
		(net "M_B_CPU1_SB_CB<5>")
	)
	(segment
		(start 41.3004 -239.391698)
		(end 41.29151 -239.382808)
		(width 0.1016)
		(layer "F.Cu")
		(net "M_B_CPU1_SB_CB<5>")
	)
	(segment
		(start 88.615266 -243.644928)
		(end 88.615012 -243.644674)
		(width 0.20066)
		(layer "F.Cu")
		(net "M_B_CPU1_SB_CB<5>")
	)
	(segment
		(start 43.795188 -239.391698)
		(end 43.616626 -239.391698)
		(width 0.20066)
		(layer "F.Cu")
		(net "M_B_CPU1_SB_CB<5>")
	)
	(segment
		(start 62.746636 -238.779812)
		(end 62.746636 -239.098328)
		(width 0.18288)
		(layer "In2.Cu")
		(net "M_B_CPU1_SB_CB<5>")
	)
	(segment
		(start 58.63336 -238.56823)
		(end 55.995824 -238.56823)
		(width 0.18288)
		(layer "In2.Cu")
		(net "M_B_CPU1_SB_CB<5>")
	)
	(segment
		(start 55.160164 -237.73257)
		(end 52.065174 -237.73257)
		(width 0.18288)
		(layer "In2.Cu")
		(net "M_B_CPU1_SB_CB<5>")
	)
	(segment
		(start 74.282554 -243.192046)
		(end 71.29526 -240.204752)
		(width 0.18288)
		(layer "In2.Cu")
		(net "M_B_CPU1_SB_CB<5>")
	)
	(segment
		(start 55.995824 -238.56823)
		(end 55.160164 -237.73257)
		(width 0.18288)
		(layer "In2.Cu")
		(net "M_B_CPU1_SB_CB<5>")
	)
	(segment
		(start 83.43392 -243.192046)
		(end 83.064096 -243.192046)
		(width 0.088646)
		(layer "In2.Cu")
		(net "M_B_CPU1_SB_CB<5>")
	)
	(segment
		(start 47.814738 -239.81664)
		(end 46.964346 -239.81664)
		(width 0.18288)
		(layer "In2.Cu")
		(net "M_B_CPU1_SB_CB<5>")
	)
	(segment
		(start 83.064096 -243.192046)
		(end 74.282554 -243.192046)
		(width 0.18288)
		(layer "In2.Cu")
		(net "M_B_CPU1_SB_CB<5>")
	)
	(segment
		(start 52.065174 -237.73257)
		(end 51.25593 -238.541814)
		(width 0.18288)
		(layer "In2.Cu")
		(net "M_B_CPU1_SB_CB<5>")
	)
	(segment
		(start 65.599818 -238.586772)
		(end 62.939676 -238.586772)
		(width 0.18288)
		(layer "In2.Cu")
		(net "M_B_CPU1_SB_CB<5>")
	)
	(segment
		(start 48.624744 -238.733838)
		(end 48.193198 -238.302292)
		(width 0.18288)
		(layer "In2.Cu")
		(net "M_B_CPU1_SB_CB<5>")
	)
	(segment
		(start 47.693834 -238.801656)
		(end 48.12538 -239.233202)
		(width 0.18288)
		(layer "In2.Cu")
		(net "M_B_CPU1_SB_CB<5>")
	)
	(segment
		(start 47.920402 -238.302292)
		(end 47.693834 -238.52886)
		(width 0.18288)
		(layer "In2.Cu")
		(net "M_B_CPU1_SB_CB<5>")
	)
	(segment
		(start 59.484768 -239.419638)
		(end 58.63336 -238.56823)
		(width 0.18288)
		(layer "In2.Cu")
		(net "M_B_CPU1_SB_CB<5>")
	)
	(segment
		(start 48.193198 -238.302292)
		(end 47.920402 -238.302292)
		(width 0.18288)
		(layer "In2.Cu")
		(net "M_B_CPU1_SB_CB<5>")
	)
	(segment
		(start 67.388486 -238.586518)
		(end 65.600072 -238.586518)
		(width 0.18288)
		(layer "In2.Cu")
		(net "M_B_CPU1_SB_CB<5>")
	)
	(segment
		(start 49.518316 -237.729522)
		(end 49.325276 -237.922562)
		(width 0.18288)
		(layer "In2.Cu")
		(net "M_B_CPU1_SB_CB<5>")
	)
	(segment
		(start 47.693834 -238.52886)
		(end 47.693834 -238.801656)
		(width 0.18288)
		(layer "In2.Cu")
		(net "M_B_CPU1_SB_CB<5>")
	)
	(segment
		(start 62.746636 -239.098328)
		(end 62.425326 -239.419638)
		(width 0.18288)
		(layer "In2.Cu")
		(net "M_B_CPU1_SB_CB<5>")
	)
	(segment
		(start 83.727544 -243.48567)
		(end 83.43392 -243.192046)
		(width 0.088646)
		(layer "In2.Cu")
		(net "M_B_CPU1_SB_CB<5>")
	)
	(segment
		(start 83.908138 -243.48567)
		(end 83.727544 -243.48567)
		(width 0.088646)
		(layer "In2.Cu")
		(net "M_B_CPU1_SB_CB<5>")
	)
	(segment
		(start 49.325276 -237.922562)
		(end 49.325276 -238.34217)
		(width 0.18288)
		(layer "In2.Cu")
		(net "M_B_CPU1_SB_CB<5>")
	)
	(segment
		(start 50.273458 -238.348774)
		(end 50.273458 -237.922562)
		(width 0.18288)
		(layer "In2.Cu")
		(net "M_B_CPU1_SB_CB<5>")
	)
	(segment
		(start 65.600072 -238.586518)
		(end 65.599818 -238.586772)
		(width 0.18288)
		(layer "In2.Cu")
		(net "M_B_CPU1_SB_CB<5>")
	)
	(segment
		(start 50.273458 -237.922562)
		(end 50.080418 -237.729522)
		(width 0.18288)
		(layer "In2.Cu")
		(net "M_B_CPU1_SB_CB<5>")
	)
	(segment
		(start 87.890604 -243.41709)
		(end 87.862664 -243.433346)
		(width 0.088646)
		(layer "In2.Cu")
		(net "M_B_CPU1_SB_CB<5>")
	)
	(segment
		(start 50.080418 -237.729522)
		(end 49.518316 -237.729522)
		(width 0.18288)
		(layer "In2.Cu")
		(net "M_B_CPU1_SB_CB<5>")
	)
	(segment
		(start 48.12538 -239.233202)
		(end 48.12538 -239.505998)
		(width 0.18288)
		(layer "In2.Cu")
		(net "M_B_CPU1_SB_CB<5>")
	)
	(segment
		(start 51.25593 -238.541814)
		(end 50.466498 -238.541814)
		(width 0.18288)
		(layer "In2.Cu")
		(net "M_B_CPU1_SB_CB<5>")
	)
	(segment
		(start 62.939676 -238.586772)
		(end 62.746636 -238.779812)
		(width 0.18288)
		(layer "In2.Cu")
		(net "M_B_CPU1_SB_CB<5>")
	)
	(segment
		(start 62.425326 -239.419638)
		(end 59.484768 -239.419638)
		(width 0.18288)
		(layer "In2.Cu")
		(net "M_B_CPU1_SB_CB<5>")
	)
	(segment
		(start 50.466498 -238.541814)
		(end 50.273458 -238.348774)
		(width 0.18288)
		(layer "In2.Cu")
		(net "M_B_CPU1_SB_CB<5>")
	)
	(segment
		(start 48.933608 -238.733838)
		(end 48.624744 -238.733838)
		(width 0.18288)
		(layer "In2.Cu")
		(net "M_B_CPU1_SB_CB<5>")
	)
	(segment
		(start 49.325276 -238.34217)
		(end 48.933608 -238.733838)
		(width 0.18288)
		(layer "In2.Cu")
		(net "M_B_CPU1_SB_CB<5>")
	)
	(segment
		(start 84.118196 -243.42471)
		(end 84.103464 -243.433346)
		(width 0.088646)
		(layer "In2.Cu")
		(net "M_B_CPU1_SB_CB<5>")
	)
	(segment
		(start 48.12538 -239.505998)
		(end 47.814738 -239.81664)
		(width 0.18288)
		(layer "In2.Cu")
		(net "M_B_CPU1_SB_CB<5>")
	)
	(segment
		(start 71.29526 -240.204752)
		(end 67.388486 -238.586518)
		(width 0.18288)
		(layer "In2.Cu")
		(net "M_B_CPU1_SB_CB<5>")
	)
	(segment
		(start 85.057996 -243.42471)
		(end 85.043264 -243.433346)
		(width 0.088646)
		(layer "In2.Cu")
		(net "M_B_CPU1_SB_CB<5>")
	)
	(segment
		(start 88.615012 -243.108988)
		(end 87.890604 -243.41709)
		(width 0.088646)
		(layer "In2.Cu")
		(net "M_B_CPU1_SB_CB<5>")
	)
	(arc
		(start 84.668868 -243.433346)
		(mid 84.394669 -243.357511)
		(end 84.118196 -243.42471)
		(width 0.088646)
		(layer "In2.Cu")
		(net "M_B_CPU1_SB_CB<5>")
	)
	(arc
		(start 85.043264 -243.433346)
		(mid 84.856066 -243.483489)
		(end 84.668868 -243.433346)
		(width 0.088646)
		(layer "In2.Cu")
		(net "M_B_CPU1_SB_CB<5>")
	)
	(arc
		(start 85.608668 -243.433346)
		(mid 85.334469 -243.357511)
		(end 85.057996 -243.42471)
		(width 0.088646)
		(layer "In2.Cu")
		(net "M_B_CPU1_SB_CB<5>")
	)
	(arc
		(start 84.103464 -243.433346)
		(mid 84.009242 -243.472346)
		(end 83.908138 -243.48567)
		(width 0.088646)
		(layer "In2.Cu")
		(net "M_B_CPU1_SB_CB<5>")
	)
	(arc
		(start 86.548468 -243.433346)
		(mid 86.265766 -243.35757)
		(end 85.983064 -243.433346)
		(width 0.088646)
		(layer "In2.Cu")
		(net "M_B_CPU1_SB_CB<5>")
	)
	(arc
		(start 87.862664 -243.433346)
		(mid 87.675466 -243.483489)
		(end 87.488268 -243.433346)
		(width 0.088646)
		(layer "In2.Cu")
		(net "M_B_CPU1_SB_CB<5>")
	)
	(arc
		(start 86.922864 -243.433346)
		(mid 86.735666 -243.483489)
		(end 86.548468 -243.433346)
		(width 0.088646)
		(layer "In2.Cu")
		(net "M_B_CPU1_SB_CB<5>")
	)
	(arc
		(start 87.488268 -243.433346)
		(mid 87.205566 -243.35757)
		(end 86.922864 -243.433346)
		(width 0.088646)
		(layer "In2.Cu")
		(net "M_B_CPU1_SB_CB<5>")
	)
	(arc
		(start 85.983064 -243.433346)
		(mid 85.795866 -243.483489)
		(end 85.608668 -243.433346)
		(width 0.088646)
		(layer "In2.Cu")
		(net "M_B_CPU1_SB_CB<5>")
	)
	(segment
		(start 44.065444 -241.09172)
		(end 43.616626 -241.09172)
		(width 0.20066)
		(layer "F.Cu")
		(net "M_B_CPU1_SB_CB<4>")
	)
	(segment
		(start 40.520112 -241.582702)
		(end 40.347392 -241.755422)
		(width 0.20066)
		(layer "F.Cu")
		(net "M_B_CPU1_SB_CB<4>")
	)
	(segment
		(start 40.347392 -241.755422)
		(end 39.888668 -241.755422)
		(width 0.20066)
		(layer "F.Cu")
		(net "M_B_CPU1_SB_CB<4>")
	)
	(segment
		(start 41.299638 -241.09172)
		(end 41.29151 -241.083592)
		(width 0.101854)
		(layer "F.Cu")
		(net "M_B_CPU1_SB_CB<4>")
	)
	(segment
		(start 39.888668 -241.755422)
		(end 39.649908 -241.516662)
		(width 0.20066)
		(layer "F.Cu")
		(net "M_B_CPU1_SB_CB<4>")
	)
	(segment
		(start 45.859446 -241.516662)
		(end 44.490386 -241.516662)
		(width 0.20066)
		(layer "F.Cu")
		(net "M_B_CPU1_SB_CB<4>")
	)
	(segment
		(start 40.520112 -241.293142)
		(end 40.520112 -241.582702)
		(width 0.20066)
		(layer "F.Cu")
		(net "M_B_CPU1_SB_CB<4>")
	)
	(segment
		(start 89.084912 -244.458744)
		(end 89.085166 -244.45849)
		(width 0.20066)
		(layer "F.Cu")
		(net "M_B_CPU1_SB_CB<4>")
	)
	(segment
		(start 39.649908 -241.516662)
		(end 38.315646 -241.516662)
		(width 0.20066)
		(layer "F.Cu")
		(net "M_B_CPU1_SB_CB<4>")
	)
	(segment
		(start 46.964346 -241.516662)
		(end 45.859446 -241.516662)
		(width 0.20066)
		(layer "F.Cu")
		(net "M_B_CPU1_SB_CB<4>")
	)
	(segment
		(start 41.29151 -241.083592)
		(end 40.729662 -241.083592)
		(width 0.20066)
		(layer "F.Cu")
		(net "M_B_CPU1_SB_CB<4>")
	)
	(segment
		(start 44.490386 -241.516662)
		(end 44.065444 -241.09172)
		(width 0.20066)
		(layer "F.Cu")
		(net "M_B_CPU1_SB_CB<4>")
	)
	(segment
		(start 40.729662 -241.083592)
		(end 40.520112 -241.293142)
		(width 0.20066)
		(layer "F.Cu")
		(net "M_B_CPU1_SB_CB<4>")
	)
	(segment
		(start 43.616626 -241.09172)
		(end 41.547542 -241.09172)
		(width 0.1016)
		(layer "F.Cu")
		(net "M_B_CPU1_SB_CB<4>")
	)
	(segment
		(start 41.547542 -241.09172)
		(end 41.299638 -241.09172)
		(width 0.101854)
		(layer "F.Cu")
		(net "M_B_CPU1_SB_CB<4>")
	)
	(segment
		(start 89.085166 -244.45849)
		(end 89.085166 -243.922804)
		(width 0.20066)
		(layer "F.Cu")
		(net "M_B_CPU1_SB_CB<4>")
	)
	(segment
		(start 48.944784 -240.377472)
		(end 48.253142 -240.377472)
		(width 0.18288)
		(layer "In2.Cu")
		(net "M_B_CPU1_SB_CB<4>")
	)
	(segment
		(start 60.320428 -240.915952)
		(end 60.097416 -241.138964)
		(width 0.18288)
		(layer "In2.Cu")
		(net "M_B_CPU1_SB_CB<4>")
	)
	(segment
		(start 71.768462 -242.131342)
		(end 69.25818 -242.131342)
		(width 0.18288)
		(layer "In2.Cu")
		(net "M_B_CPU1_SB_CB<4>")
	)
	(segment
		(start 55.291482 -239.577372)
		(end 54.453282 -239.577372)
		(width 0.18288)
		(layer "In2.Cu")
		(net "M_B_CPU1_SB_CB<4>")
	)
	(segment
		(start 83.39328 -243.882926)
		(end 83.064096 -243.882926)
		(width 0.088646)
		(layer "In2.Cu")
		(net "M_B_CPU1_SB_CB<4>")
	)
	(segment
		(start 65.7225 -240.013236)
		(end 64.39281 -240.013236)
		(width 0.18288)
		(layer "In2.Cu")
		(net "M_B_CPU1_SB_CB<4>")
	)
	(segment
		(start 64.111378 -240.294668)
		(end 63.699644 -240.294668)
		(width 0.18288)
		(layer "In2.Cu")
		(net "M_B_CPU1_SB_CB<4>")
	)
	(segment
		(start 89.085166 -243.922804)
		(end 88.702388 -244.073934)
		(width 0.088646)
		(layer "In2.Cu")
		(net "M_B_CPU1_SB_CB<4>")
	)
	(segment
		(start 47.245778 -241.798094)
		(end 46.964346 -241.516662)
		(width 0.18288)
		(layer "In2.Cu")
		(net "M_B_CPU1_SB_CB<4>")
	)
	(segment
		(start 63.699644 -240.294668)
		(end 62.85357 -241.140742)
		(width 0.18288)
		(layer "In2.Cu")
		(net "M_B_CPU1_SB_CB<4>")
	)
	(segment
		(start 62.85357 -241.140742)
		(end 61.895482 -241.140742)
		(width 0.18288)
		(layer "In2.Cu")
		(net "M_B_CPU1_SB_CB<4>")
	)
	(segment
		(start 69.06514 -240.899696)
		(end 68.8721 -240.706656)
		(width 0.18288)
		(layer "In2.Cu")
		(net "M_B_CPU1_SB_CB<4>")
	)
	(segment
		(start 47.867062 -241.798094)
		(end 47.245778 -241.798094)
		(width 0.18288)
		(layer "In2.Cu")
		(net "M_B_CPU1_SB_CB<4>")
	)
	(segment
		(start 55.98922 -240.27511)
		(end 55.291482 -239.577372)
		(width 0.18288)
		(layer "In2.Cu")
		(net "M_B_CPU1_SB_CB<4>")
	)
	(segment
		(start 83.064096 -243.882926)
		(end 73.520046 -243.882926)
		(width 0.18288)
		(layer "In2.Cu")
		(net "M_B_CPU1_SB_CB<4>")
	)
	(segment
		(start 47.862998 -240.767616)
		(end 47.862998 -241.175286)
		(width 0.18288)
		(layer "In2.Cu")
		(net "M_B_CPU1_SB_CB<4>")
	)
	(segment
		(start 61.670692 -240.915952)
		(end 60.320428 -240.915952)
		(width 0.18288)
		(layer "In2.Cu")
		(net "M_B_CPU1_SB_CB<4>")
	)
	(segment
		(start 52.527454 -239.395)
		(end 49.636172 -239.395)
		(width 0.18288)
		(layer "In2.Cu")
		(net "M_B_CPU1_SB_CB<4>")
	)
	(segment
		(start 66.41592 -240.706656)
		(end 65.7225 -240.013236)
		(width 0.18288)
		(layer "In2.Cu")
		(net "M_B_CPU1_SB_CB<4>")
	)
	(segment
		(start 59.687968 -241.138964)
		(end 59.091576 -240.542572)
		(width 0.18288)
		(layer "In2.Cu")
		(net "M_B_CPU1_SB_CB<4>")
	)
	(segment
		(start 64.39281 -240.013236)
		(end 64.111378 -240.294668)
		(width 0.18288)
		(layer "In2.Cu")
		(net "M_B_CPU1_SB_CB<4>")
	)
	(segment
		(start 59.091576 -240.542572)
		(end 58.589926 -240.542572)
		(width 0.18288)
		(layer "In2.Cu")
		(net "M_B_CPU1_SB_CB<4>")
	)
	(segment
		(start 56.72836 -240.156492)
		(end 56.609742 -240.27511)
		(width 0.18288)
		(layer "In2.Cu")
		(net "M_B_CPU1_SB_CB<4>")
	)
	(segment
		(start 83.839304 -244.150642)
		(end 83.660996 -244.150642)
		(width 0.088646)
		(layer "In2.Cu")
		(net "M_B_CPU1_SB_CB<4>")
	)
	(segment
		(start 48.060102 -241.605054)
		(end 47.867062 -241.798094)
		(width 0.18288)
		(layer "In2.Cu")
		(net "M_B_CPU1_SB_CB<4>")
	)
	(segment
		(start 49.636172 -239.395)
		(end 49.39411 -239.637062)
		(width 0.18288)
		(layer "In2.Cu")
		(net "M_B_CPU1_SB_CB<4>")
	)
	(segment
		(start 56.609742 -240.27511)
		(end 55.98922 -240.27511)
		(width 0.18288)
		(layer "In2.Cu")
		(net "M_B_CPU1_SB_CB<4>")
	)
	(segment
		(start 54.199282 -239.323372)
		(end 52.599082 -239.323372)
		(width 0.18288)
		(layer "In2.Cu")
		(net "M_B_CPU1_SB_CB<4>")
	)
	(segment
		(start 54.453282 -239.577372)
		(end 54.199282 -239.323372)
		(width 0.18288)
		(layer "In2.Cu")
		(net "M_B_CPU1_SB_CB<4>")
	)
	(segment
		(start 86.467696 -244.238526)
		(end 86.452964 -244.247162)
		(width 0.088646)
		(layer "In2.Cu")
		(net "M_B_CPU1_SB_CB<4>")
	)
	(segment
		(start 73.520046 -243.882926)
		(end 71.768462 -242.131342)
		(width 0.18288)
		(layer "In2.Cu")
		(net "M_B_CPU1_SB_CB<4>")
	)
	(segment
		(start 60.097416 -241.138964)
		(end 59.687968 -241.138964)
		(width 0.18288)
		(layer "In2.Cu")
		(net "M_B_CPU1_SB_CB<4>")
	)
	(segment
		(start 69.06514 -241.938302)
		(end 69.06514 -240.899696)
		(width 0.18288)
		(layer "In2.Cu")
		(net "M_B_CPU1_SB_CB<4>")
	)
	(segment
		(start 47.862998 -241.175286)
		(end 48.060102 -241.37239)
		(width 0.18288)
		(layer "In2.Cu")
		(net "M_B_CPU1_SB_CB<4>")
	)
	(segment
		(start 87.407496 -244.238526)
		(end 87.392764 -244.247162)
		(width 0.088646)
		(layer "In2.Cu")
		(net "M_B_CPU1_SB_CB<4>")
	)
	(segment
		(start 58.203846 -240.156492)
		(end 56.72836 -240.156492)
		(width 0.18288)
		(layer "In2.Cu")
		(net "M_B_CPU1_SB_CB<4>")
	)
	(segment
		(start 49.39411 -239.928146)
		(end 48.944784 -240.377472)
		(width 0.18288)
		(layer "In2.Cu")
		(net "M_B_CPU1_SB_CB<4>")
	)
	(segment
		(start 84.588096 -244.238526)
		(end 84.573364 -244.247162)
		(width 0.088646)
		(layer "In2.Cu")
		(net "M_B_CPU1_SB_CB<4>")
	)
	(segment
		(start 48.253142 -240.377472)
		(end 47.862998 -240.767616)
		(width 0.18288)
		(layer "In2.Cu")
		(net "M_B_CPU1_SB_CB<4>")
	)
	(segment
		(start 52.599082 -239.323372)
		(end 52.527454 -239.395)
		(width 0.18288)
		(layer "In2.Cu")
		(net "M_B_CPU1_SB_CB<4>")
	)
	(segment
		(start 83.660996 -244.150642)
		(end 83.39328 -243.882926)
		(width 0.088646)
		(layer "In2.Cu")
		(net "M_B_CPU1_SB_CB<4>")
	)
	(segment
		(start 69.25818 -242.131342)
		(end 69.06514 -241.938302)
		(width 0.18288)
		(layer "In2.Cu")
		(net "M_B_CPU1_SB_CB<4>")
	)
	(segment
		(start 88.427052 -244.19179)
		(end 88.332564 -244.247162)
		(width 0.088646)
		(layer "In2.Cu")
		(net "M_B_CPU1_SB_CB<4>")
	)
	(segment
		(start 85.527896 -244.238526)
		(end 85.513164 -244.247162)
		(width 0.088646)
		(layer "In2.Cu")
		(net "M_B_CPU1_SB_CB<4>")
	)
	(segment
		(start 49.39411 -239.637062)
		(end 49.39411 -239.928146)
		(width 0.18288)
		(layer "In2.Cu")
		(net "M_B_CPU1_SB_CB<4>")
	)
	(segment
		(start 61.895482 -241.140742)
		(end 61.670692 -240.915952)
		(width 0.18288)
		(layer "In2.Cu")
		(net "M_B_CPU1_SB_CB<4>")
	)
	(segment
		(start 88.702388 -244.073934)
		(end 88.427052 -244.19179)
		(width 0.088646)
		(layer "In2.Cu")
		(net "M_B_CPU1_SB_CB<4>")
	)
	(segment
		(start 68.8721 -240.706656)
		(end 66.41592 -240.706656)
		(width 0.18288)
		(layer "In2.Cu")
		(net "M_B_CPU1_SB_CB<4>")
	)
	(segment
		(start 58.589926 -240.542572)
		(end 58.203846 -240.156492)
		(width 0.18288)
		(layer "In2.Cu")
		(net "M_B_CPU1_SB_CB<4>")
	)
	(segment
		(start 48.060102 -241.37239)
		(end 48.060102 -241.605054)
		(width 0.18288)
		(layer "In2.Cu")
		(net "M_B_CPU1_SB_CB<4>")
	)
	(arc
		(start 84.198968 -244.247162)
		(mid 84.0255 -244.175186)
		(end 83.839304 -244.150642)
		(width 0.088646)
		(layer "In2.Cu")
		(net "M_B_CPU1_SB_CB<4>")
	)
	(arc
		(start 85.513164 -244.247162)
		(mid 85.325966 -244.297305)
		(end 85.138768 -244.247162)
		(width 0.088646)
		(layer "In2.Cu")
		(net "M_B_CPU1_SB_CB<4>")
	)
	(arc
		(start 84.573364 -244.247162)
		(mid 84.386166 -244.297305)
		(end 84.198968 -244.247162)
		(width 0.088646)
		(layer "In2.Cu")
		(net "M_B_CPU1_SB_CB<4>")
	)
	(arc
		(start 87.958168 -244.247162)
		(mid 87.683969 -244.171327)
		(end 87.407496 -244.238526)
		(width 0.088646)
		(layer "In2.Cu")
		(net "M_B_CPU1_SB_CB<4>")
	)
	(arc
		(start 87.392764 -244.247162)
		(mid 87.205566 -244.297305)
		(end 87.018368 -244.247162)
		(width 0.088646)
		(layer "In2.Cu")
		(net "M_B_CPU1_SB_CB<4>")
	)
	(arc
		(start 86.452964 -244.247162)
		(mid 86.265766 -244.297305)
		(end 86.078568 -244.247162)
		(width 0.088646)
		(layer "In2.Cu")
		(net "M_B_CPU1_SB_CB<4>")
	)
	(arc
		(start 85.138768 -244.247162)
		(mid 84.864569 -244.171327)
		(end 84.588096 -244.238526)
		(width 0.088646)
		(layer "In2.Cu")
		(net "M_B_CPU1_SB_CB<4>")
	)
	(arc
		(start 88.332564 -244.247162)
		(mid 88.145366 -244.297305)
		(end 87.958168 -244.247162)
		(width 0.088646)
		(layer "In2.Cu")
		(net "M_B_CPU1_SB_CB<4>")
	)
	(arc
		(start 87.018368 -244.247162)
		(mid 86.744169 -244.171327)
		(end 86.467696 -244.238526)
		(width 0.088646)
		(layer "In2.Cu")
		(net "M_B_CPU1_SB_CB<4>")
	)
	(arc
		(start 86.078568 -244.247162)
		(mid 85.804369 -244.171327)
		(end 85.527896 -244.238526)
		(width 0.088646)
		(layer "In2.Cu")
		(net "M_B_CPU1_SB_CB<4>")
	)
	(segment
		(start 90.024966 -241.202972)
		(end 90.024966 -240.667286)
		(width 0.20066)
		(layer "F.Cu")
		(net "M_B_CPU1_SB_CB<3>")
	)
	(segment
		(start 47.882302 -233.012488)
		(end 47.753778 -233.141012)
		(width 0.20066)
		(layer "F.Cu")
		(net "M_B_CPU1_SB_CB<3>")
	)
	(segment
		(start 48.935894 -233.224324)
		(end 48.489362 -233.224324)
		(width 0.20066)
		(layer "F.Cu")
		(net "M_B_CPU1_SB_CB<3>")
	)
	(segment
		(start 44.749466 -233.441748)
		(end 44.735242 -233.455972)
		(width 0.101854)
		(layer "F.Cu")
		(net "M_B_CPU1_SB_CB<3>")
	)
	(segment
		(start 44.735242 -233.455972)
		(end 44.38142 -233.455972)
		(width 0.20066)
		(layer "F.Cu")
		(net "M_B_CPU1_SB_CB<3>")
	)
	(segment
		(start 44.238926 -233.14279)
		(end 44.112942 -233.016806)
		(width 0.20066)
		(layer "F.Cu")
		(net "M_B_CPU1_SB_CB<3>")
	)
	(segment
		(start 49.959514 -233.016806)
		(end 49.143412 -233.016806)
		(width 0.20066)
		(layer "F.Cu")
		(net "M_B_CPU1_SB_CB<3>")
	)
	(segment
		(start 47.753778 -233.29265)
		(end 47.60468 -233.441748)
		(width 0.20066)
		(layer "F.Cu")
		(net "M_B_CPU1_SB_CB<3>")
	)
	(segment
		(start 47.060358 -233.441748)
		(end 44.987464 -233.441748)
		(width 0.1016)
		(layer "F.Cu")
		(net "M_B_CPU1_SB_CB<3>")
	)
	(segment
		(start 90.024712 -241.203226)
		(end 90.024966 -241.202972)
		(width 0.20066)
		(layer "F.Cu")
		(net "M_B_CPU1_SB_CB<3>")
	)
	(segment
		(start 48.277526 -233.012488)
		(end 47.882302 -233.012488)
		(width 0.20066)
		(layer "F.Cu")
		(net "M_B_CPU1_SB_CB<3>")
	)
	(segment
		(start 47.60468 -233.441748)
		(end 47.060358 -233.441748)
		(width 0.20066)
		(layer "F.Cu")
		(net "M_B_CPU1_SB_CB<3>")
	)
	(segment
		(start 51.064414 -233.016806)
		(end 49.959514 -233.016806)
		(width 0.20066)
		(layer "F.Cu")
		(net "M_B_CPU1_SB_CB<3>")
	)
	(segment
		(start 44.238926 -233.313478)
		(end 44.238926 -233.14279)
		(width 0.20066)
		(layer "F.Cu")
		(net "M_B_CPU1_SB_CB<3>")
	)
	(segment
		(start 44.38142 -233.455972)
		(end 44.238926 -233.313478)
		(width 0.20066)
		(layer "F.Cu")
		(net "M_B_CPU1_SB_CB<3>")
	)
	(segment
		(start 44.112942 -233.016806)
		(end 42.415714 -233.016806)
		(width 0.20066)
		(layer "F.Cu")
		(net "M_B_CPU1_SB_CB<3>")
	)
	(segment
		(start 48.489362 -233.224324)
		(end 48.277526 -233.012488)
		(width 0.20066)
		(layer "F.Cu")
		(net "M_B_CPU1_SB_CB<3>")
	)
	(segment
		(start 49.143412 -233.016806)
		(end 48.935894 -233.224324)
		(width 0.20066)
		(layer "F.Cu")
		(net "M_B_CPU1_SB_CB<3>")
	)
	(segment
		(start 47.753778 -233.141012)
		(end 47.753778 -233.29265)
		(width 0.20066)
		(layer "F.Cu")
		(net "M_B_CPU1_SB_CB<3>")
	)
	(segment
		(start 44.987464 -233.441748)
		(end 44.749466 -233.441748)
		(width 0.101854)
		(layer "F.Cu")
		(net "M_B_CPU1_SB_CB<3>")
	)
	(segment
		(start 69.574664 -234.828588)
		(end 69.333618 -234.587542)
		(width 0.18288)
		(layer "In2.Cu")
		(net "M_B_CPU1_SB_CB<3>")
	)
	(segment
		(start 90.00617 -240.69929)
		(end 89.664286 -240.791238)
		(width 0.088646)
		(layer "In2.Cu")
		(net "M_B_CPU1_SB_CB<3>")
	)
	(segment
		(start 88.897968 -240.991644)
		(end 88.833452 -240.954306)
		(width 0.088646)
		(layer "In2.Cu")
		(net "M_B_CPU1_SB_CB<3>")
	)
	(segment
		(start 63.709296 -233.303572)
		(end 63.402464 -233.610404)
		(width 0.18288)
		(layer "In2.Cu")
		(net "M_B_CPU1_SB_CB<3>")
	)
	(segment
		(start 65.85204 -233.56316)
		(end 64.242188 -233.56316)
		(width 0.18288)
		(layer "In2.Cu")
		(net "M_B_CPU1_SB_CB<3>")
	)
	(segment
		(start 65.9765 -233.4387)
		(end 65.85204 -233.56316)
		(width 0.18288)
		(layer "In2.Cu")
		(net "M_B_CPU1_SB_CB<3>")
	)
	(segment
		(start 69.140578 -233.825288)
		(end 68.563998 -233.825288)
		(width 0.18288)
		(layer "In2.Cu")
		(net "M_B_CPU1_SB_CB<3>")
	)
	(segment
		(start 67.86118 -234.79125)
		(end 67.51955 -234.44962)
		(width 0.18288)
		(layer "In2.Cu")
		(net "M_B_CPU1_SB_CB<3>")
	)
	(segment
		(start 89.582244 -240.82375)
		(end 89.272364 -240.991644)
		(width 0.088646)
		(layer "In2.Cu")
		(net "M_B_CPU1_SB_CB<3>")
	)
	(segment
		(start 76.64704 -240.824766)
		(end 70.650862 -234.828588)
		(width 0.18288)
		(layer "In2.Cu")
		(net "M_B_CPU1_SB_CB<3>")
	)
	(segment
		(start 84.120736 -240.401856)
		(end 83.697826 -240.824766)
		(width 0.088646)
		(layer "In2.Cu")
		(net "M_B_CPU1_SB_CB<3>")
	)
	(segment
		(start 56.504332 -232.731818)
		(end 56.231282 -232.731818)
		(width 0.18288)
		(layer "In2.Cu")
		(net "M_B_CPU1_SB_CB<3>")
	)
	(segment
		(start 59.380882 -232.794048)
		(end 59.187588 -232.600754)
		(width 0.18288)
		(layer "In2.Cu")
		(net "M_B_CPU1_SB_CB<3>")
	)
	(segment
		(start 68.370958 -234.018328)
		(end 68.370958 -234.59821)
		(width 0.18288)
		(layer "In2.Cu")
		(net "M_B_CPU1_SB_CB<3>")
	)
	(segment
		(start 67.376802 -233.780838)
		(end 66.550286 -233.4387)
		(width 0.18288)
		(layer "In2.Cu")
		(net "M_B_CPU1_SB_CB<3>")
	)
	(segment
		(start 68.370958 -234.59821)
		(end 68.177918 -234.79125)
		(width 0.18288)
		(layer "In2.Cu")
		(net "M_B_CPU1_SB_CB<3>")
	)
	(segment
		(start 66.550286 -233.4387)
		(end 65.9765 -233.4387)
		(width 0.18288)
		(layer "In2.Cu")
		(net "M_B_CPU1_SB_CB<3>")
	)
	(segment
		(start 52.413662 -232.462832)
		(end 51.618388 -232.462832)
		(width 0.18288)
		(layer "In2.Cu")
		(net "M_B_CPU1_SB_CB<3>")
	)
	(segment
		(start 87.407496 -240.351564)
		(end 87.392764 -240.342928)
		(width 0.088646)
		(layer "In2.Cu")
		(net "M_B_CPU1_SB_CB<3>")
	)
	(segment
		(start 69.333618 -234.018328)
		(end 69.140578 -233.825288)
		(width 0.18288)
		(layer "In2.Cu")
		(net "M_B_CPU1_SB_CB<3>")
	)
	(segment
		(start 67.51955 -233.923586)
		(end 67.376802 -233.780838)
		(width 0.18288)
		(layer "In2.Cu")
		(net "M_B_CPU1_SB_CB<3>")
	)
	(segment
		(start 63.402464 -233.610404)
		(end 62.032134 -233.610404)
		(width 0.18288)
		(layer "In2.Cu")
		(net "M_B_CPU1_SB_CB<3>")
	)
	(segment
		(start 55.949596 -231.711246)
		(end 55.646574 -231.408224)
		(width 0.18288)
		(layer "In2.Cu")
		(net "M_B_CPU1_SB_CB<3>")
	)
	(segment
		(start 52.883308 -232.932478)
		(end 52.413662 -232.462832)
		(width 0.18288)
		(layer "In2.Cu")
		(net "M_B_CPU1_SB_CB<3>")
	)
	(segment
		(start 63.9826 -233.303572)
		(end 63.709296 -233.303572)
		(width 0.18288)
		(layer "In2.Cu")
		(net "M_B_CPU1_SB_CB<3>")
	)
	(segment
		(start 54.553104 -231.875838)
		(end 54.553104 -232.34777)
		(width 0.18288)
		(layer "In2.Cu")
		(net "M_B_CPU1_SB_CB<3>")
	)
	(segment
		(start 55.646574 -231.408224)
		(end 55.020718 -231.408224)
		(width 0.18288)
		(layer "In2.Cu")
		(net "M_B_CPU1_SB_CB<3>")
	)
	(segment
		(start 53.968396 -232.932478)
		(end 52.883308 -232.932478)
		(width 0.18288)
		(layer "In2.Cu")
		(net "M_B_CPU1_SB_CB<3>")
	)
	(segment
		(start 67.51955 -234.44962)
		(end 67.51955 -233.923586)
		(width 0.18288)
		(layer "In2.Cu")
		(net "M_B_CPU1_SB_CB<3>")
	)
	(segment
		(start 55.020718 -231.408224)
		(end 54.553104 -231.875838)
		(width 0.18288)
		(layer "In2.Cu")
		(net "M_B_CPU1_SB_CB<3>")
	)
	(segment
		(start 59.187588 -232.600754)
		(end 58.356754 -232.600754)
		(width 0.18288)
		(layer "In2.Cu")
		(net "M_B_CPU1_SB_CB<3>")
	)
	(segment
		(start 88.833452 -240.954306)
		(end 88.701626 -240.834926)
		(width 0.088646)
		(layer "In2.Cu")
		(net "M_B_CPU1_SB_CB<3>")
	)
	(segment
		(start 60.374784 -233.112056)
		(end 60.010802 -233.476038)
		(width 0.18288)
		(layer "In2.Cu")
		(net "M_B_CPU1_SB_CB<3>")
	)
	(segment
		(start 83.064096 -240.824766)
		(end 76.64704 -240.824766)
		(width 0.18288)
		(layer "In2.Cu")
		(net "M_B_CPU1_SB_CB<3>")
	)
	(segment
		(start 68.563998 -233.825288)
		(end 68.370958 -234.018328)
		(width 0.18288)
		(layer "In2.Cu")
		(net "M_B_CPU1_SB_CB<3>")
	)
	(segment
		(start 88.701626 -240.834926)
		(end 88.504268 -240.55959)
		(width 0.088646)
		(layer "In2.Cu")
		(net "M_B_CPU1_SB_CB<3>")
	)
	(segment
		(start 58.205878 -232.449878)
		(end 56.786272 -232.449878)
		(width 0.18288)
		(layer "In2.Cu")
		(net "M_B_CPU1_SB_CB<3>")
	)
	(segment
		(start 55.949596 -232.450132)
		(end 55.949596 -231.711246)
		(width 0.18288)
		(layer "In2.Cu")
		(net "M_B_CPU1_SB_CB<3>")
	)
	(segment
		(start 90.024966 -240.667286)
		(end 90.00617 -240.69929)
		(width 0.088646)
		(layer "In2.Cu")
		(net "M_B_CPU1_SB_CB<3>")
	)
	(segment
		(start 62.032134 -233.610404)
		(end 61.533786 -233.112056)
		(width 0.18288)
		(layer "In2.Cu")
		(net "M_B_CPU1_SB_CB<3>")
	)
	(segment
		(start 83.697826 -240.824766)
		(end 83.064096 -240.824766)
		(width 0.088646)
		(layer "In2.Cu")
		(net "M_B_CPU1_SB_CB<3>")
	)
	(segment
		(start 64.242188 -233.56316)
		(end 63.9826 -233.303572)
		(width 0.18288)
		(layer "In2.Cu")
		(net "M_B_CPU1_SB_CB<3>")
	)
	(segment
		(start 84.588096 -240.351564)
		(end 84.573364 -240.342928)
		(width 0.088646)
		(layer "In2.Cu")
		(net "M_B_CPU1_SB_CB<3>")
	)
	(segment
		(start 56.231282 -232.731818)
		(end 55.949596 -232.450132)
		(width 0.18288)
		(layer "In2.Cu")
		(net "M_B_CPU1_SB_CB<3>")
	)
	(segment
		(start 60.010802 -233.476038)
		(end 59.654948 -233.476038)
		(width 0.18288)
		(layer "In2.Cu")
		(net "M_B_CPU1_SB_CB<3>")
	)
	(segment
		(start 54.553104 -232.34777)
		(end 53.968396 -232.932478)
		(width 0.18288)
		(layer "In2.Cu")
		(net "M_B_CPU1_SB_CB<3>")
	)
	(segment
		(start 85.527896 -240.351564)
		(end 85.513164 -240.342928)
		(width 0.088646)
		(layer "In2.Cu")
		(net "M_B_CPU1_SB_CB<3>")
	)
	(segment
		(start 69.333618 -234.587542)
		(end 69.333618 -234.018328)
		(width 0.18288)
		(layer "In2.Cu")
		(net "M_B_CPU1_SB_CB<3>")
	)
	(segment
		(start 59.380882 -233.201972)
		(end 59.380882 -232.794048)
		(width 0.18288)
		(layer "In2.Cu")
		(net "M_B_CPU1_SB_CB<3>")
	)
	(segment
		(start 86.467696 -240.351564)
		(end 86.452964 -240.342928)
		(width 0.088646)
		(layer "In2.Cu")
		(net "M_B_CPU1_SB_CB<3>")
	)
	(segment
		(start 56.786272 -232.449878)
		(end 56.504332 -232.731818)
		(width 0.18288)
		(layer "In2.Cu")
		(net "M_B_CPU1_SB_CB<3>")
	)
	(segment
		(start 70.650862 -234.828588)
		(end 69.574664 -234.828588)
		(width 0.18288)
		(layer "In2.Cu")
		(net "M_B_CPU1_SB_CB<3>")
	)
	(segment
		(start 59.654948 -233.476038)
		(end 59.380882 -233.201972)
		(width 0.18288)
		(layer "In2.Cu")
		(net "M_B_CPU1_SB_CB<3>")
	)
	(segment
		(start 61.533786 -233.112056)
		(end 60.374784 -233.112056)
		(width 0.18288)
		(layer "In2.Cu")
		(net "M_B_CPU1_SB_CB<3>")
	)
	(segment
		(start 88.341454 -240.348008)
		(end 88.332564 -240.342928)
		(width 0.088646)
		(layer "In2.Cu")
		(net "M_B_CPU1_SB_CB<3>")
	)
	(segment
		(start 68.177918 -234.79125)
		(end 67.86118 -234.79125)
		(width 0.18288)
		(layer "In2.Cu")
		(net "M_B_CPU1_SB_CB<3>")
	)
	(segment
		(start 51.618388 -232.462832)
		(end 51.064414 -233.016806)
		(width 0.18288)
		(layer "In2.Cu")
		(net "M_B_CPU1_SB_CB<3>")
	)
	(segment
		(start 58.356754 -232.600754)
		(end 58.205878 -232.449878)
		(width 0.18288)
		(layer "In2.Cu")
		(net "M_B_CPU1_SB_CB<3>")
	)
	(arc
		(start 86.452964 -240.342928)
		(mid 86.265766 -240.292785)
		(end 86.078568 -240.342928)
		(width 0.088646)
		(layer "In2.Cu")
		(net "M_B_CPU1_SB_CB<3>")
	)
	(arc
		(start 88.504268 -240.55959)
		(mid 88.442326 -240.43883)
		(end 88.341454 -240.348008)
		(width 0.088646)
		(layer "In2.Cu")
		(net "M_B_CPU1_SB_CB<3>")
	)
	(arc
		(start 86.078568 -240.342928)
		(mid 85.804339 -240.418853)
		(end 85.527896 -240.351564)
		(width 0.088646)
		(layer "In2.Cu")
		(net "M_B_CPU1_SB_CB<3>")
	)
	(arc
		(start 88.332564 -240.342928)
		(mid 88.145366 -240.292785)
		(end 87.958168 -240.342928)
		(width 0.088646)
		(layer "In2.Cu")
		(net "M_B_CPU1_SB_CB<3>")
	)
	(arc
		(start 84.573364 -240.342928)
		(mid 84.386166 -240.292785)
		(end 84.198968 -240.342928)
		(width 0.088646)
		(layer "In2.Cu")
		(net "M_B_CPU1_SB_CB<3>")
	)
	(arc
		(start 85.513164 -240.342928)
		(mid 85.325966 -240.292785)
		(end 85.138768 -240.342928)
		(width 0.088646)
		(layer "In2.Cu")
		(net "M_B_CPU1_SB_CB<3>")
	)
	(arc
		(start 87.392764 -240.342928)
		(mid 87.205566 -240.292785)
		(end 87.018368 -240.342928)
		(width 0.088646)
		(layer "In2.Cu")
		(net "M_B_CPU1_SB_CB<3>")
	)
	(arc
		(start 89.664286 -240.791238)
		(mid 89.622321 -240.805109)
		(end 89.582244 -240.82375)
		(width 0.088646)
		(layer "In2.Cu")
		(net "M_B_CPU1_SB_CB<3>")
	)
	(arc
		(start 84.198968 -240.342928)
		(mid 84.15791 -240.369815)
		(end 84.120736 -240.401856)
		(width 0.088646)
		(layer "In2.Cu")
		(net "M_B_CPU1_SB_CB<3>")
	)
	(arc
		(start 87.958168 -240.342928)
		(mid 87.683939 -240.418853)
		(end 87.407496 -240.351564)
		(width 0.088646)
		(layer "In2.Cu")
		(net "M_B_CPU1_SB_CB<3>")
	)
	(arc
		(start 85.138768 -240.342928)
		(mid 84.864539 -240.418853)
		(end 84.588096 -240.351564)
		(width 0.088646)
		(layer "In2.Cu")
		(net "M_B_CPU1_SB_CB<3>")
	)
	(arc
		(start 87.018368 -240.342928)
		(mid 86.744139 -240.418853)
		(end 86.467696 -240.351564)
		(width 0.088646)
		(layer "In2.Cu")
		(net "M_B_CPU1_SB_CB<3>")
	)
	(arc
		(start 89.272364 -240.991644)
		(mid 89.085166 -241.041787)
		(end 88.897968 -240.991644)
		(width 0.088646)
		(layer "In2.Cu")
		(net "M_B_CPU1_SB_CB<3>")
	)
	(segment
		(start 47.060358 -234.291632)
		(end 45.000418 -234.291632)
		(width 0.1016)
		(layer "F.Cu")
		(net "M_B_CPU1_SB_CB<2>")
	)
	(segment
		(start 47.83709 -234.435396)
		(end 47.693326 -234.291632)
		(width 0.20066)
		(layer "F.Cu")
		(net "M_B_CPU1_SB_CB<2>")
	)
	(segment
		(start 49.959514 -234.716574)
		(end 48.64481 -234.716574)
		(width 0.20066)
		(layer "F.Cu")
		(net "M_B_CPU1_SB_CB<2>")
	)
	(segment
		(start 44.745402 -234.291632)
		(end 44.735242 -234.281472)
		(width 0.101854)
		(layer "F.Cu")
		(net "M_B_CPU1_SB_CB<2>")
	)
	(segment
		(start 90.494612 -242.016788)
		(end 90.494612 -241.481102)
		(width 0.20066)
		(layer "F.Cu")
		(net "M_B_CPU1_SB_CB<2>")
	)
	(segment
		(start 43.99788 -234.281472)
		(end 43.562778 -234.716574)
		(width 0.20066)
		(layer "F.Cu")
		(net "M_B_CPU1_SB_CB<2>")
	)
	(segment
		(start 47.693326 -234.291632)
		(end 47.060358 -234.291632)
		(width 0.20066)
		(layer "F.Cu")
		(net "M_B_CPU1_SB_CB<2>")
	)
	(segment
		(start 48.432974 -234.92841)
		(end 48.004476 -234.92841)
		(width 0.20066)
		(layer "F.Cu")
		(net "M_B_CPU1_SB_CB<2>")
	)
	(segment
		(start 44.735242 -234.281472)
		(end 43.99788 -234.281472)
		(width 0.20066)
		(layer "F.Cu")
		(net "M_B_CPU1_SB_CB<2>")
	)
	(segment
		(start 45.000418 -234.291632)
		(end 44.745402 -234.291632)
		(width 0.101854)
		(layer "F.Cu")
		(net "M_B_CPU1_SB_CB<2>")
	)
	(segment
		(start 51.064414 -234.716574)
		(end 49.959514 -234.716574)
		(width 0.20066)
		(layer "F.Cu")
		(net "M_B_CPU1_SB_CB<2>")
	)
	(segment
		(start 90.494866 -242.017042)
		(end 90.494612 -242.016788)
		(width 0.20066)
		(layer "F.Cu")
		(net "M_B_CPU1_SB_CB<2>")
	)
	(segment
		(start 47.83709 -234.761024)
		(end 47.83709 -234.435396)
		(width 0.20066)
		(layer "F.Cu")
		(net "M_B_CPU1_SB_CB<2>")
	)
	(segment
		(start 48.004476 -234.92841)
		(end 47.83709 -234.761024)
		(width 0.20066)
		(layer "F.Cu")
		(net "M_B_CPU1_SB_CB<2>")
	)
	(segment
		(start 48.64481 -234.716574)
		(end 48.432974 -234.92841)
		(width 0.20066)
		(layer "F.Cu")
		(net "M_B_CPU1_SB_CB<2>")
	)
	(segment
		(start 43.562778 -234.716574)
		(end 42.415714 -234.716574)
		(width 0.20066)
		(layer "F.Cu")
		(net "M_B_CPU1_SB_CB<2>")
	)
	(segment
		(start 69.504052 -236.121956)
		(end 69.399912 -235.869734)
		(width 0.18288)
		(layer "In2.Cu")
		(net "M_B_CPU1_SB_CB<2>")
	)
	(segment
		(start 68.694808 -236.228636)
		(end 68.44284 -236.33303)
		(width 0.18288)
		(layer "In2.Cu")
		(net "M_B_CPU1_SB_CB<2>")
	)
	(segment
		(start 69.399912 -235.869734)
		(end 69.103748 -235.747052)
		(width 0.18288)
		(layer "In2.Cu")
		(net "M_B_CPU1_SB_CB<2>")
	)
	(segment
		(start 69.997828 -236.774482)
		(end 69.74586 -236.878876)
		(width 0.18288)
		(layer "In2.Cu")
		(net "M_B_CPU1_SB_CB<2>")
	)
	(segment
		(start 89.367614 -241.80546)
		(end 89.352882 -241.796824)
		(width 0.088646)
		(layer "In2.Cu")
		(net "M_B_CPU1_SB_CB<2>")
	)
	(segment
		(start 89.367868 -241.80546)
		(end 89.367614 -241.80546)
		(width 0.088646)
		(layer "In2.Cu")
		(net "M_B_CPU1_SB_CB<2>")
	)
	(segment
		(start 70.394576 -236.321854)
		(end 70.142354 -236.425994)
		(width 0.18288)
		(layer "In2.Cu")
		(net "M_B_CPU1_SB_CB<2>")
	)
	(segment
		(start 83.934808 -241.360452)
		(end 83.779614 -241.515646)
		(width 0.088646)
		(layer "In2.Cu")
		(net "M_B_CPU1_SB_CB<2>")
	)
	(segment
		(start 83.779614 -241.515646)
		(end 83.064096 -241.515646)
		(width 0.088646)
		(layer "In2.Cu")
		(net "M_B_CPU1_SB_CB<2>")
	)
	(segment
		(start 56.064912 -235.144056)
		(end 55.381144 -235.144056)
		(width 0.18288)
		(layer "In2.Cu")
		(net "M_B_CPU1_SB_CB<2>")
	)
	(segment
		(start 56.224932 -234.984036)
		(end 56.064912 -235.144056)
		(width 0.18288)
		(layer "In2.Cu")
		(net "M_B_CPU1_SB_CB<2>")
	)
	(segment
		(start 70.79488 -236.696758)
		(end 70.690486 -236.444536)
		(width 0.18288)
		(layer "In2.Cu")
		(net "M_B_CPU1_SB_CB<2>")
	)
	(segment
		(start 83.064096 -241.515646)
		(end 75.880976 -241.515646)
		(width 0.18288)
		(layer "In2.Cu")
		(net "M_B_CPU1_SB_CB<2>")
	)
	(segment
		(start 69.345302 -236.503972)
		(end 69.504052 -236.121956)
		(width 0.18288)
		(layer "In2.Cu")
		(net "M_B_CPU1_SB_CB<2>")
	)
	(segment
		(start 69.74586 -236.878876)
		(end 69.44995 -236.756194)
		(width 0.18288)
		(layer "In2.Cu")
		(net "M_B_CPU1_SB_CB<2>")
	)
	(segment
		(start 88.43645 -241.810286)
		(end 88.428068 -241.80546)
		(width 0.088646)
		(layer "In2.Cu")
		(net "M_B_CPU1_SB_CB<2>")
	)
	(segment
		(start 68.851526 -235.851192)
		(end 68.694808 -236.228636)
		(width 0.18288)
		(layer "In2.Cu")
		(net "M_B_CPU1_SB_CB<2>")
	)
	(segment
		(start 59.114182 -235.243116)
		(end 59.114182 -234.510072)
		(width 0.18288)
		(layer "In2.Cu")
		(net "M_B_CPU1_SB_CB<2>")
	)
	(segment
		(start 84.446364 -241.360452)
		(end 83.934808 -241.360452)
		(width 0.088646)
		(layer "In2.Cu")
		(net "M_B_CPU1_SB_CB<2>")
	)
	(segment
		(start 58.068718 -233.973878)
		(end 56.988202 -233.973878)
		(width 0.18288)
		(layer "In2.Cu")
		(net "M_B_CPU1_SB_CB<2>")
	)
	(segment
		(start 68.44284 -236.33303)
		(end 66.98361 -235.728002)
		(width 0.18288)
		(layer "In2.Cu")
		(net "M_B_CPU1_SB_CB<2>")
	)
	(segment
		(start 51.605434 -234.175554)
		(end 51.064414 -234.716574)
		(width 0.18288)
		(layer "In2.Cu")
		(net "M_B_CPU1_SB_CB<2>")
	)
	(segment
		(start 52.484782 -234.175554)
		(end 51.605434 -234.175554)
		(width 0.18288)
		(layer "In2.Cu")
		(net "M_B_CPU1_SB_CB<2>")
	)
	(segment
		(start 56.384952 -234.344972)
		(end 56.224932 -234.504992)
		(width 0.18288)
		(layer "In2.Cu")
		(net "M_B_CPU1_SB_CB<2>")
	)
	(segment
		(start 70.690486 -236.444536)
		(end 70.394576 -236.321854)
		(width 0.18288)
		(layer "In2.Cu")
		(net "M_B_CPU1_SB_CB<2>")
	)
	(segment
		(start 63.983362 -234.890818)
		(end 63.232284 -234.890818)
		(width 0.18288)
		(layer "In2.Cu")
		(net "M_B_CPU1_SB_CB<2>")
	)
	(segment
		(start 61.61659 -234.915456)
		(end 60.283598 -234.915456)
		(width 0.18288)
		(layer "In2.Cu")
		(net "M_B_CPU1_SB_CB<2>")
	)
	(segment
		(start 64.203834 -235.11129)
		(end 63.983362 -234.890818)
		(width 0.18288)
		(layer "In2.Cu")
		(net "M_B_CPU1_SB_CB<2>")
	)
	(segment
		(start 88.428068 -241.80546)
		(end 88.142064 -241.64036)
		(width 0.088646)
		(layer "In2.Cu")
		(net "M_B_CPU1_SB_CB<2>")
	)
	(segment
		(start 62.701932 -235.42117)
		(end 62.122304 -235.42117)
		(width 0.18288)
		(layer "In2.Cu")
		(net "M_B_CPU1_SB_CB<2>")
	)
	(segment
		(start 69.103748 -235.747052)
		(end 68.851526 -235.851192)
		(width 0.18288)
		(layer "In2.Cu")
		(net "M_B_CPU1_SB_CB<2>")
	)
	(segment
		(start 66.98361 -235.728002)
		(end 66.765932 -235.201714)
		(width 0.18288)
		(layer "In2.Cu")
		(net "M_B_CPU1_SB_CB<2>")
	)
	(segment
		(start 54.525164 -234.121198)
		(end 54.370732 -234.27563)
		(width 0.18288)
		(layer "In2.Cu")
		(net "M_B_CPU1_SB_CB<2>")
	)
	(segment
		(start 84.59089 -241.215926)
		(end 84.446364 -241.360452)
		(width 0.088646)
		(layer "In2.Cu")
		(net "M_B_CPU1_SB_CB<2>")
	)
	(segment
		(start 54.995064 -234.121198)
		(end 54.525164 -234.121198)
		(width 0.18288)
		(layer "In2.Cu")
		(net "M_B_CPU1_SB_CB<2>")
	)
	(segment
		(start 55.188104 -234.951016)
		(end 55.188104 -234.314238)
		(width 0.18288)
		(layer "In2.Cu")
		(net "M_B_CPU1_SB_CB<2>")
	)
	(segment
		(start 70.142354 -236.425994)
		(end 69.997828 -236.774482)
		(width 0.18288)
		(layer "In2.Cu")
		(net "M_B_CPU1_SB_CB<2>")
	)
	(segment
		(start 62.122304 -235.42117)
		(end 61.61659 -234.915456)
		(width 0.18288)
		(layer "In2.Cu")
		(net "M_B_CPU1_SB_CB<2>")
	)
	(segment
		(start 66.547746 -235.11129)
		(end 64.203834 -235.11129)
		(width 0.18288)
		(layer "In2.Cu")
		(net "M_B_CPU1_SB_CB<2>")
	)
	(segment
		(start 63.232284 -234.890818)
		(end 62.701932 -235.42117)
		(width 0.18288)
		(layer "In2.Cu")
		(net "M_B_CPU1_SB_CB<2>")
	)
	(segment
		(start 56.617108 -234.344972)
		(end 56.384952 -234.344972)
		(width 0.18288)
		(layer "In2.Cu")
		(net "M_B_CPU1_SB_CB<2>")
	)
	(segment
		(start 56.224932 -234.504992)
		(end 56.224932 -234.984036)
		(width 0.18288)
		(layer "In2.Cu")
		(net "M_B_CPU1_SB_CB<2>")
	)
	(segment
		(start 54.370732 -234.27563)
		(end 52.584858 -234.27563)
		(width 0.18288)
		(layer "In2.Cu")
		(net "M_B_CPU1_SB_CB<2>")
	)
	(segment
		(start 55.381144 -235.144056)
		(end 55.188104 -234.951016)
		(width 0.18288)
		(layer "In2.Cu")
		(net "M_B_CPU1_SB_CB<2>")
	)
	(segment
		(start 70.656196 -237.031276)
		(end 70.79488 -236.696758)
		(width 0.18288)
		(layer "In2.Cu")
		(net "M_B_CPU1_SB_CB<2>")
	)
	(segment
		(start 70.76186 -237.28553)
		(end 70.656196 -237.031276)
		(width 0.18288)
		(layer "In2.Cu")
		(net "M_B_CPU1_SB_CB<2>")
	)
	(segment
		(start 75.880976 -241.515646)
		(end 72.277224 -237.911894)
		(width 0.18288)
		(layer "In2.Cu")
		(net "M_B_CPU1_SB_CB<2>")
	)
	(segment
		(start 59.762644 -235.43641)
		(end 59.307476 -235.43641)
		(width 0.18288)
		(layer "In2.Cu")
		(net "M_B_CPU1_SB_CB<2>")
	)
	(segment
		(start 60.283598 -234.915456)
		(end 59.762644 -235.43641)
		(width 0.18288)
		(layer "In2.Cu")
		(net "M_B_CPU1_SB_CB<2>")
	)
	(segment
		(start 55.188104 -234.314238)
		(end 54.995064 -234.121198)
		(width 0.18288)
		(layer "In2.Cu")
		(net "M_B_CPU1_SB_CB<2>")
	)
	(segment
		(start 58.439812 -234.344972)
		(end 58.068718 -233.973878)
		(width 0.18288)
		(layer "In2.Cu")
		(net "M_B_CPU1_SB_CB<2>")
	)
	(segment
		(start 72.277224 -237.911894)
		(end 70.76186 -237.28553)
		(width 0.18288)
		(layer "In2.Cu")
		(net "M_B_CPU1_SB_CB<2>")
	)
	(segment
		(start 90.494612 -241.481102)
		(end 89.770712 -241.78895)
		(width 0.088646)
		(layer "In2.Cu")
		(net "M_B_CPU1_SB_CB<2>")
	)
	(segment
		(start 69.44995 -236.756194)
		(end 69.345302 -236.503972)
		(width 0.18288)
		(layer "In2.Cu")
		(net "M_B_CPU1_SB_CB<2>")
	)
	(segment
		(start 52.584858 -234.27563)
		(end 52.484782 -234.175554)
		(width 0.18288)
		(layer "In2.Cu")
		(net "M_B_CPU1_SB_CB<2>")
	)
	(segment
		(start 58.949082 -234.344972)
		(end 58.439812 -234.344972)
		(width 0.18288)
		(layer "In2.Cu")
		(net "M_B_CPU1_SB_CB<2>")
	)
	(segment
		(start 59.307476 -235.43641)
		(end 59.114182 -235.243116)
		(width 0.18288)
		(layer "In2.Cu")
		(net "M_B_CPU1_SB_CB<2>")
	)
	(segment
		(start 56.988202 -233.973878)
		(end 56.617108 -234.344972)
		(width 0.18288)
		(layer "In2.Cu")
		(net "M_B_CPU1_SB_CB<2>")
	)
	(segment
		(start 66.765932 -235.201714)
		(end 66.547746 -235.11129)
		(width 0.18288)
		(layer "In2.Cu")
		(net "M_B_CPU1_SB_CB<2>")
	)
	(segment
		(start 59.114182 -234.510072)
		(end 58.949082 -234.344972)
		(width 0.18288)
		(layer "In2.Cu")
		(net "M_B_CPU1_SB_CB<2>")
	)
	(segment
		(start 89.770712 -241.78895)
		(end 89.742264 -241.80546)
		(width 0.088646)
		(layer "In2.Cu")
		(net "M_B_CPU1_SB_CB<2>")
	)
	(arc
		(start 88.80221 -241.80546)
		(mid 88.619959 -241.855571)
		(end 88.43645 -241.810286)
		(width 0.088646)
		(layer "In2.Cu")
		(net "M_B_CPU1_SB_CB<2>")
	)
	(arc
		(start 86.548468 -241.156744)
		(mid 86.265766 -241.23252)
		(end 85.983064 -241.156744)
		(width 0.088646)
		(layer "In2.Cu")
		(net "M_B_CPU1_SB_CB<2>")
	)
	(arc
		(start 85.043264 -241.156744)
		(mid 84.856066 -241.106601)
		(end 84.668868 -241.156744)
		(width 0.088646)
		(layer "In2.Cu")
		(net "M_B_CPU1_SB_CB<2>")
	)
	(arc
		(start 87.488268 -241.156744)
		(mid 87.205566 -241.23252)
		(end 86.922864 -241.156744)
		(width 0.088646)
		(layer "In2.Cu")
		(net "M_B_CPU1_SB_CB<2>")
	)
	(arc
		(start 84.668868 -241.156744)
		(mid 84.627938 -241.183777)
		(end 84.59089 -241.215926)
		(width 0.088646)
		(layer "In2.Cu")
		(net "M_B_CPU1_SB_CB<2>")
	)
	(arc
		(start 89.352882 -241.796824)
		(mid 89.076407 -241.729504)
		(end 88.80221 -241.80546)
		(width 0.088646)
		(layer "In2.Cu")
		(net "M_B_CPU1_SB_CB<2>")
	)
	(arc
		(start 85.608668 -241.156744)
		(mid 85.325966 -241.23252)
		(end 85.043264 -241.156744)
		(width 0.088646)
		(layer "In2.Cu")
		(net "M_B_CPU1_SB_CB<2>")
	)
	(arc
		(start 86.922864 -241.156744)
		(mid 86.735666 -241.106601)
		(end 86.548468 -241.156744)
		(width 0.088646)
		(layer "In2.Cu")
		(net "M_B_CPU1_SB_CB<2>")
	)
	(arc
		(start 85.983064 -241.156744)
		(mid 85.795866 -241.106601)
		(end 85.608668 -241.156744)
		(width 0.088646)
		(layer "In2.Cu")
		(net "M_B_CPU1_SB_CB<2>")
	)
	(arc
		(start 88.142064 -241.64036)
		(mid 88.074575 -241.573113)
		(end 88.049862 -241.481102)
		(width 0.088646)
		(layer "In2.Cu")
		(net "M_B_CPU1_SB_CB<2>")
	)
	(arc
		(start 88.049862 -241.481102)
		(mid 87.999708 -241.293846)
		(end 87.862664 -241.156744)
		(width 0.088646)
		(layer "In2.Cu")
		(net "M_B_CPU1_SB_CB<2>")
	)
	(arc
		(start 89.742264 -241.80546)
		(mid 89.555066 -241.855637)
		(end 89.367868 -241.80546)
		(width 0.088646)
		(layer "In2.Cu")
		(net "M_B_CPU1_SB_CB<2>")
	)
	(arc
		(start 87.862664 -241.156744)
		(mid 87.675466 -241.106601)
		(end 87.488268 -241.156744)
		(width 0.088646)
		(layer "In2.Cu")
		(net "M_B_CPU1_SB_CB<2>")
	)
	(segment
		(start 46.964346 -233.86669)
		(end 45.859446 -233.86669)
		(width 0.20066)
		(layer "F.Cu")
		(net "M_B_CPU1_SB_CB<1>")
	)
	(segment
		(start 40.520112 -233.923586)
		(end 40.36568 -234.078018)
		(width 0.20066)
		(layer "F.Cu")
		(net "M_B_CPU1_SB_CB<1>")
	)
	(segment
		(start 40.682672 -233.432858)
		(end 40.520112 -233.595418)
		(width 0.20066)
		(layer "F.Cu")
		(net "M_B_CPU1_SB_CB<1>")
	)
	(segment
		(start 41.3004 -233.441748)
		(end 41.29151 -233.432858)
		(width 0.1016)
		(layer "F.Cu")
		(net "M_B_CPU1_SB_CB<1>")
	)
	(segment
		(start 89.085166 -241.202972)
		(end 89.085166 -240.667286)
		(width 0.20066)
		(layer "F.Cu")
		(net "M_B_CPU1_SB_CB<1>")
	)
	(segment
		(start 44.22013 -233.86669)
		(end 43.795188 -233.441748)
		(width 0.20066)
		(layer "F.Cu")
		(net "M_B_CPU1_SB_CB<1>")
	)
	(segment
		(start 40.36568 -234.078018)
		(end 39.861236 -234.078018)
		(width 0.20066)
		(layer "F.Cu")
		(net "M_B_CPU1_SB_CB<1>")
	)
	(segment
		(start 43.616626 -233.441748)
		(end 43.285918 -233.441748)
		(width 0.101854)
		(layer "F.Cu")
		(net "M_B_CPU1_SB_CB<1>")
	)
	(segment
		(start 39.649908 -233.86669)
		(end 38.315646 -233.86669)
		(width 0.20066)
		(layer "F.Cu")
		(net "M_B_CPU1_SB_CB<1>")
	)
	(segment
		(start 43.795188 -233.441748)
		(end 43.616626 -233.441748)
		(width 0.20066)
		(layer "F.Cu")
		(net "M_B_CPU1_SB_CB<1>")
	)
	(segment
		(start 89.084912 -241.203226)
		(end 89.085166 -241.202972)
		(width 0.20066)
		(layer "F.Cu")
		(net "M_B_CPU1_SB_CB<1>")
	)
	(segment
		(start 41.29151 -233.432858)
		(end 40.682672 -233.432858)
		(width 0.20066)
		(layer "F.Cu")
		(net "M_B_CPU1_SB_CB<1>")
	)
	(segment
		(start 40.520112 -233.595418)
		(end 40.520112 -233.923586)
		(width 0.20066)
		(layer "F.Cu")
		(net "M_B_CPU1_SB_CB<1>")
	)
	(segment
		(start 43.285918 -233.441748)
		(end 41.3004 -233.441748)
		(width 0.1016)
		(layer "F.Cu")
		(net "M_B_CPU1_SB_CB<1>")
	)
	(segment
		(start 39.861236 -234.078018)
		(end 39.649908 -233.86669)
		(width 0.20066)
		(layer "F.Cu")
		(net "M_B_CPU1_SB_CB<1>")
	)
	(segment
		(start 45.859446 -233.86669)
		(end 44.22013 -233.86669)
		(width 0.20066)
		(layer "F.Cu")
		(net "M_B_CPU1_SB_CB<1>")
	)
	(segment
		(start 48.188118 -232.642918)
		(end 46.964346 -233.86669)
		(width 0.18288)
		(layer "In2.Cu")
		(net "M_B_CPU1_SB_CB<1>")
	)
	(segment
		(start 66.324734 -232.877868)
		(end 65.796414 -232.659174)
		(width 0.18288)
		(layer "In2.Cu")
		(net "M_B_CPU1_SB_CB<1>")
	)
	(segment
		(start 83.064096 -240.479326)
		(end 77.024484 -240.479326)
		(width 0.18288)
		(layer "In2.Cu")
		(net "M_B_CPU1_SB_CB<1>")
	)
	(segment
		(start 63.212218 -232.990136)
		(end 62.714378 -232.990136)
		(width 0.18288)
		(layer "In2.Cu")
		(net "M_B_CPU1_SB_CB<1>")
	)
	(segment
		(start 51.674268 -231.930956)
		(end 51.485038 -231.741726)
		(width 0.18288)
		(layer "In2.Cu")
		(net "M_B_CPU1_SB_CB<1>")
	)
	(segment
		(start 58.60415 -231.51973)
		(end 58.184796 -231.939084)
		(width 0.18288)
		(layer "In2.Cu")
		(net "M_B_CPU1_SB_CB<1>")
	)
	(segment
		(start 62.714378 -232.990136)
		(end 62.316106 -232.591864)
		(width 0.18288)
		(layer "In2.Cu")
		(net "M_B_CPU1_SB_CB<1>")
	)
	(segment
		(start 49.856136 -232.592372)
		(end 49.176686 -232.592372)
		(width 0.18288)
		(layer "In2.Cu")
		(net "M_B_CPU1_SB_CB<1>")
	)
	(segment
		(start 86.548214 -240.177574)
		(end 86.533482 -240.168938)
		(width 0.088646)
		(layer "In2.Cu")
		(net "M_B_CPU1_SB_CB<1>")
	)
	(segment
		(start 67.597528 -233.310938)
		(end 66.551048 -232.877868)
		(width 0.18288)
		(layer "In2.Cu")
		(net "M_B_CPU1_SB_CB<1>")
	)
	(segment
		(start 83.774026 -240.479326)
		(end 83.064096 -240.479326)
		(width 0.088646)
		(layer "In2.Cu")
		(net "M_B_CPU1_SB_CB<1>")
	)
	(segment
		(start 58.184796 -231.939084)
		(end 56.902096 -231.939084)
		(width 0.18288)
		(layer "In2.Cu")
		(net "M_B_CPU1_SB_CB<1>")
	)
	(segment
		(start 49.089056 -232.642918)
		(end 48.188118 -232.642918)
		(width 0.18288)
		(layer "In2.Cu")
		(net "M_B_CPU1_SB_CB<1>")
	)
	(segment
		(start 83.986116 -240.267236)
		(end 83.774026 -240.479326)
		(width 0.088646)
		(layer "In2.Cu")
		(net "M_B_CPU1_SB_CB<1>")
	)
	(segment
		(start 52.319936 -231.930956)
		(end 51.674268 -231.930956)
		(width 0.18288)
		(layer "In2.Cu")
		(net "M_B_CPU1_SB_CB<1>")
	)
	(segment
		(start 85.608414 -240.177574)
		(end 85.593682 -240.168938)
		(width 0.088646)
		(layer "In2.Cu")
		(net "M_B_CPU1_SB_CB<1>")
	)
	(segment
		(start 89.085166 -240.667286)
		(end 88.629744 -240.375694)
		(width 0.088646)
		(layer "In2.Cu")
		(net "M_B_CPU1_SB_CB<1>")
	)
	(segment
		(start 51.485038 -231.741726)
		(end 50.706782 -231.741726)
		(width 0.18288)
		(layer "In2.Cu")
		(net "M_B_CPU1_SB_CB<1>")
	)
	(segment
		(start 77.024484 -240.479326)
		(end 69.856096 -233.310938)
		(width 0.18288)
		(layer "In2.Cu")
		(net "M_B_CPU1_SB_CB<1>")
	)
	(segment
		(start 87.488014 -240.177574)
		(end 87.473282 -240.168938)
		(width 0.088646)
		(layer "In2.Cu")
		(net "M_B_CPU1_SB_CB<1>")
	)
	(segment
		(start 65.796414 -232.659174)
		(end 63.54318 -232.659174)
		(width 0.18288)
		(layer "In2.Cu")
		(net "M_B_CPU1_SB_CB<1>")
	)
	(segment
		(start 59.12104 -231.51973)
		(end 58.60415 -231.51973)
		(width 0.18288)
		(layer "In2.Cu")
		(net "M_B_CPU1_SB_CB<1>")
	)
	(segment
		(start 55.839868 -230.876856)
		(end 53.374036 -230.876856)
		(width 0.18288)
		(layer "In2.Cu")
		(net "M_B_CPU1_SB_CB<1>")
	)
	(segment
		(start 53.374036 -230.876856)
		(end 52.319936 -231.930956)
		(width 0.18288)
		(layer "In2.Cu")
		(net "M_B_CPU1_SB_CB<1>")
	)
	(segment
		(start 84.668614 -240.177574)
		(end 84.653882 -240.168938)
		(width 0.088646)
		(layer "In2.Cu")
		(net "M_B_CPU1_SB_CB<1>")
	)
	(segment
		(start 50.706782 -231.741726)
		(end 49.856136 -232.592372)
		(width 0.18288)
		(layer "In2.Cu")
		(net "M_B_CPU1_SB_CB<1>")
	)
	(segment
		(start 69.856096 -233.310938)
		(end 67.597528 -233.310938)
		(width 0.18288)
		(layer "In2.Cu")
		(net "M_B_CPU1_SB_CB<1>")
	)
	(segment
		(start 62.316106 -232.591864)
		(end 60.193174 -232.591864)
		(width 0.18288)
		(layer "In2.Cu")
		(net "M_B_CPU1_SB_CB<1>")
	)
	(segment
		(start 63.54318 -232.659174)
		(end 63.212218 -232.990136)
		(width 0.18288)
		(layer "In2.Cu")
		(net "M_B_CPU1_SB_CB<1>")
	)
	(segment
		(start 88.427814 -240.177574)
		(end 88.413082 -240.168938)
		(width 0.088646)
		(layer "In2.Cu")
		(net "M_B_CPU1_SB_CB<1>")
	)
	(segment
		(start 49.176686 -232.592372)
		(end 49.089056 -232.642918)
		(width 0.18288)
		(layer "In2.Cu")
		(net "M_B_CPU1_SB_CB<1>")
	)
	(segment
		(start 66.551048 -232.877868)
		(end 66.324734 -232.877868)
		(width 0.18288)
		(layer "In2.Cu")
		(net "M_B_CPU1_SB_CB<1>")
	)
	(segment
		(start 60.193174 -232.591864)
		(end 59.12104 -231.51973)
		(width 0.18288)
		(layer "In2.Cu")
		(net "M_B_CPU1_SB_CB<1>")
	)
	(segment
		(start 56.902096 -231.939084)
		(end 55.839868 -230.876856)
		(width 0.18288)
		(layer "In2.Cu")
		(net "M_B_CPU1_SB_CB<1>")
	)
	(arc
		(start 87.86241 -240.177574)
		(mid 87.675212 -240.227717)
		(end 87.488014 -240.177574)
		(width 0.088646)
		(layer "In2.Cu")
		(net "M_B_CPU1_SB_CB<1>")
	)
	(arc
		(start 84.10321 -240.177574)
		(mid 84.041725 -240.218569)
		(end 83.986116 -240.267236)
		(width 0.088646)
		(layer "In2.Cu")
		(net "M_B_CPU1_SB_CB<1>")
	)
	(arc
		(start 86.92261 -240.177574)
		(mid 86.735412 -240.227717)
		(end 86.548214 -240.177574)
		(width 0.088646)
		(layer "In2.Cu")
		(net "M_B_CPU1_SB_CB<1>")
	)
	(arc
		(start 87.473282 -240.168938)
		(mid 87.196841 -240.101772)
		(end 86.92261 -240.177574)
		(width 0.088646)
		(layer "In2.Cu")
		(net "M_B_CPU1_SB_CB<1>")
	)
	(arc
		(start 85.593682 -240.168938)
		(mid 85.317241 -240.101772)
		(end 85.04301 -240.177574)
		(width 0.088646)
		(layer "In2.Cu")
		(net "M_B_CPU1_SB_CB<1>")
	)
	(arc
		(start 88.629744 -240.375694)
		(mid 88.541386 -240.263781)
		(end 88.427814 -240.177574)
		(width 0.088646)
		(layer "In2.Cu")
		(net "M_B_CPU1_SB_CB<1>")
	)
	(arc
		(start 84.653882 -240.168938)
		(mid 84.377441 -240.101772)
		(end 84.10321 -240.177574)
		(width 0.088646)
		(layer "In2.Cu")
		(net "M_B_CPU1_SB_CB<1>")
	)
	(arc
		(start 88.413082 -240.168938)
		(mid 88.136641 -240.101772)
		(end 87.86241 -240.177574)
		(width 0.088646)
		(layer "In2.Cu")
		(net "M_B_CPU1_SB_CB<1>")
	)
	(arc
		(start 85.98281 -240.177574)
		(mid 85.795612 -240.227717)
		(end 85.608414 -240.177574)
		(width 0.088646)
		(layer "In2.Cu")
		(net "M_B_CPU1_SB_CB<1>")
	)
	(arc
		(start 86.533482 -240.168938)
		(mid 86.257041 -240.101772)
		(end 85.98281 -240.177574)
		(width 0.088646)
		(layer "In2.Cu")
		(net "M_B_CPU1_SB_CB<1>")
	)
	(arc
		(start 85.04301 -240.177574)
		(mid 84.855812 -240.227717)
		(end 84.668614 -240.177574)
		(width 0.088646)
		(layer "In2.Cu")
		(net "M_B_CPU1_SB_CB<1>")
	)
	(segment
		(start 39.649908 -235.566712)
		(end 38.315646 -235.566712)
		(width 0.20066)
		(layer "F.Cu")
		(net "M_B_CPU1_SB_CB<0>")
	)
	(segment
		(start 41.299638 -235.14177)
		(end 41.29151 -235.133642)
		(width 0.101854)
		(layer "F.Cu")
		(net "M_B_CPU1_SB_CB<0>")
	)
	(segment
		(start 41.29151 -235.133642)
		(end 40.729662 -235.133642)
		(width 0.20066)
		(layer "F.Cu")
		(net "M_B_CPU1_SB_CB<0>")
	)
	(segment
		(start 88.615012 -242.016788)
		(end 88.615012 -241.481102)
		(width 0.20066)
		(layer "F.Cu")
		(net "M_B_CPU1_SB_CB<0>")
	)
	(segment
		(start 40.347392 -235.805472)
		(end 39.888668 -235.805472)
		(width 0.20066)
		(layer "F.Cu")
		(net "M_B_CPU1_SB_CB<0>")
	)
	(segment
		(start 44.490386 -235.566712)
		(end 44.065444 -235.14177)
		(width 0.20066)
		(layer "F.Cu")
		(net "M_B_CPU1_SB_CB<0>")
	)
	(segment
		(start 88.615266 -242.017042)
		(end 88.615012 -242.016788)
		(width 0.20066)
		(layer "F.Cu")
		(net "M_B_CPU1_SB_CB<0>")
	)
	(segment
		(start 41.547542 -235.14177)
		(end 41.299638 -235.14177)
		(width 0.101854)
		(layer "F.Cu")
		(net "M_B_CPU1_SB_CB<0>")
	)
	(segment
		(start 40.729662 -235.133642)
		(end 40.520112 -235.343192)
		(width 0.20066)
		(layer "F.Cu")
		(net "M_B_CPU1_SB_CB<0>")
	)
	(segment
		(start 46.964346 -235.566712)
		(end 45.859446 -235.566712)
		(width 0.20066)
		(layer "F.Cu")
		(net "M_B_CPU1_SB_CB<0>")
	)
	(segment
		(start 45.859446 -235.566712)
		(end 44.490386 -235.566712)
		(width 0.20066)
		(layer "F.Cu")
		(net "M_B_CPU1_SB_CB<0>")
	)
	(segment
		(start 40.520112 -235.343192)
		(end 40.520112 -235.632752)
		(width 0.20066)
		(layer "F.Cu")
		(net "M_B_CPU1_SB_CB<0>")
	)
	(segment
		(start 40.520112 -235.632752)
		(end 40.347392 -235.805472)
		(width 0.20066)
		(layer "F.Cu")
		(net "M_B_CPU1_SB_CB<0>")
	)
	(segment
		(start 44.065444 -235.14177)
		(end 43.616626 -235.14177)
		(width 0.20066)
		(layer "F.Cu")
		(net "M_B_CPU1_SB_CB<0>")
	)
	(segment
		(start 39.888668 -235.805472)
		(end 39.649908 -235.566712)
		(width 0.20066)
		(layer "F.Cu")
		(net "M_B_CPU1_SB_CB<0>")
	)
	(segment
		(start 43.616626 -235.14177)
		(end 41.547542 -235.14177)
		(width 0.1016)
		(layer "F.Cu")
		(net "M_B_CPU1_SB_CB<0>")
	)
	(segment
		(start 59.421014 -234.026456)
		(end 58.79973 -233.405172)
		(width 0.18288)
		(layer "In2.Cu")
		(net "M_B_CPU1_SB_CB<0>")
	)
	(segment
		(start 55.906924 -233.405172)
		(end 55.713884 -233.212132)
		(width 0.18288)
		(layer "In2.Cu")
		(net "M_B_CPU1_SB_CB<0>")
	)
	(segment
		(start 83.064096 -241.170206)
		(end 76.264008 -241.170206)
		(width 0.18288)
		(layer "In2.Cu")
		(net "M_B_CPU1_SB_CB<0>")
	)
	(segment
		(start 55.713884 -232.955084)
		(end 55.520844 -232.762044)
		(width 0.18288)
		(layer "In2.Cu")
		(net "M_B_CPU1_SB_CB<0>")
	)
	(segment
		(start 48.057308 -234.47375)
		(end 47.82693 -234.704128)
		(width 0.18288)
		(layer "In2.Cu")
		(net "M_B_CPU1_SB_CB<0>")
	)
	(segment
		(start 66.215514 -234.588558)
		(end 65.698116 -234.07116)
		(width 0.18288)
		(layer "In2.Cu")
		(net "M_B_CPU1_SB_CB<0>")
	)
	(segment
		(start 61.671708 -234.399836)
		(end 60.26277 -234.399836)
		(width 0.18288)
		(layer "In2.Cu")
		(net "M_B_CPU1_SB_CB<0>")
	)
	(segment
		(start 52.427124 -233.64825)
		(end 51.476656 -233.64825)
		(width 0.18288)
		(layer "In2.Cu")
		(net "M_B_CPU1_SB_CB<0>")
	)
	(segment
		(start 87.986362 -241.007646)
		(end 87.958168 -240.991644)
		(width 0.088646)
		(layer "In2.Cu")
		(net "M_B_CPU1_SB_CB<0>")
	)
	(segment
		(start 68.221352 -235.561378)
		(end 68.020946 -235.561378)
		(width 0.18288)
		(layer "In2.Cu")
		(net "M_B_CPU1_SB_CB<0>")
	)
	(segment
		(start 54.746144 -233.560366)
		(end 54.360572 -233.560366)
		(width 0.18288)
		(layer "In2.Cu")
		(net "M_B_CPU1_SB_CB<0>")
	)
	(segment
		(start 70.874128 -235.787946)
		(end 70.531228 -235.787946)
		(width 0.18288)
		(layer "In2.Cu")
		(net "M_B_CPU1_SB_CB<0>")
	)
	(segment
		(start 68.020946 -235.561378)
		(end 67.836034 -235.48467)
		(width 0.18288)
		(layer "In2.Cu")
		(net "M_B_CPU1_SB_CB<0>")
	)
	(segment
		(start 71.299324 -236.213142)
		(end 70.874128 -235.787946)
		(width 0.18288)
		(layer "In2.Cu")
		(net "M_B_CPU1_SB_CB<0>")
	)
	(segment
		(start 55.713884 -233.212132)
		(end 55.713884 -232.955084)
		(width 0.18288)
		(layer "In2.Cu")
		(net "M_B_CPU1_SB_CB<0>")
	)
	(segment
		(start 54.939184 -232.955084)
		(end 54.939184 -233.367326)
		(width 0.18288)
		(layer "In2.Cu")
		(net "M_B_CPU1_SB_CB<0>")
	)
	(segment
		(start 71.299324 -236.61878)
		(end 71.299324 -236.213142)
		(width 0.18288)
		(layer "In2.Cu")
		(net "M_B_CPU1_SB_CB<0>")
	)
	(segment
		(start 49.949354 -233.441748)
		(end 48.917352 -234.47375)
		(width 0.18288)
		(layer "In2.Cu")
		(net "M_B_CPU1_SB_CB<0>")
	)
	(segment
		(start 84.45627 -241.081306)
		(end 84.36737 -241.170206)
		(width 0.088646)
		(layer "In2.Cu")
		(net "M_B_CPU1_SB_CB<0>")
	)
	(segment
		(start 47.63389 -235.566712)
		(end 46.964346 -235.566712)
		(width 0.18288)
		(layer "In2.Cu")
		(net "M_B_CPU1_SB_CB<0>")
	)
	(segment
		(start 60.26277 -234.399836)
		(end 59.88939 -234.026456)
		(width 0.18288)
		(layer "In2.Cu")
		(net "M_B_CPU1_SB_CB<0>")
	)
	(segment
		(start 66.939922 -234.588558)
		(end 66.215514 -234.588558)
		(width 0.18288)
		(layer "In2.Cu")
		(net "M_B_CPU1_SB_CB<0>")
	)
	(segment
		(start 52.632864 -233.44251)
		(end 52.427124 -233.64825)
		(width 0.18288)
		(layer "In2.Cu")
		(net "M_B_CPU1_SB_CB<0>")
	)
	(segment
		(start 51.476656 -233.64825)
		(end 51.270154 -233.441748)
		(width 0.18288)
		(layer "In2.Cu")
		(net "M_B_CPU1_SB_CB<0>")
	)
	(segment
		(start 76.264008 -241.170206)
		(end 72.228202 -237.1344)
		(width 0.18288)
		(layer "In2.Cu")
		(net "M_B_CPU1_SB_CB<0>")
	)
	(segment
		(start 47.82693 -234.704128)
		(end 47.82693 -235.373672)
		(width 0.18288)
		(layer "In2.Cu")
		(net "M_B_CPU1_SB_CB<0>")
	)
	(segment
		(start 55.520844 -232.762044)
		(end 55.132224 -232.762044)
		(width 0.18288)
		(layer "In2.Cu")
		(net "M_B_CPU1_SB_CB<0>")
	)
	(segment
		(start 67.836034 -235.48467)
		(end 66.939922 -234.588558)
		(width 0.18288)
		(layer "In2.Cu")
		(net "M_B_CPU1_SB_CB<0>")
	)
	(segment
		(start 64.424052 -234.07116)
		(end 64.11976 -234.375452)
		(width 0.18288)
		(layer "In2.Cu")
		(net "M_B_CPU1_SB_CB<0>")
	)
	(segment
		(start 64.11976 -234.375452)
		(end 63.147194 -234.375452)
		(width 0.18288)
		(layer "In2.Cu")
		(net "M_B_CPU1_SB_CB<0>")
	)
	(segment
		(start 54.242716 -233.44251)
		(end 52.632864 -233.44251)
		(width 0.18288)
		(layer "In2.Cu")
		(net "M_B_CPU1_SB_CB<0>")
	)
	(segment
		(start 58.79973 -233.405172)
		(end 55.906924 -233.405172)
		(width 0.18288)
		(layer "In2.Cu")
		(net "M_B_CPU1_SB_CB<0>")
	)
	(segment
		(start 55.132224 -232.762044)
		(end 54.939184 -232.955084)
		(width 0.18288)
		(layer "In2.Cu")
		(net "M_B_CPU1_SB_CB<0>")
	)
	(segment
		(start 88.615012 -241.481102)
		(end 87.986362 -241.007646)
		(width 0.088646)
		(layer "In2.Cu")
		(net "M_B_CPU1_SB_CB<0>")
	)
	(segment
		(start 71.814944 -237.1344)
		(end 71.299324 -236.61878)
		(width 0.18288)
		(layer "In2.Cu")
		(net "M_B_CPU1_SB_CB<0>")
	)
	(segment
		(start 51.270154 -233.441748)
		(end 49.949354 -233.441748)
		(width 0.18288)
		(layer "In2.Cu")
		(net "M_B_CPU1_SB_CB<0>")
	)
	(segment
		(start 72.228202 -237.1344)
		(end 71.814944 -237.1344)
		(width 0.18288)
		(layer "In2.Cu")
		(net "M_B_CPU1_SB_CB<0>")
	)
	(segment
		(start 59.88939 -234.026456)
		(end 59.421014 -234.026456)
		(width 0.18288)
		(layer "In2.Cu")
		(net "M_B_CPU1_SB_CB<0>")
	)
	(segment
		(start 70.531228 -235.787946)
		(end 69.201792 -235.237528)
		(width 0.18288)
		(layer "In2.Cu")
		(net "M_B_CPU1_SB_CB<0>")
	)
	(segment
		(start 65.698116 -234.07116)
		(end 64.424052 -234.07116)
		(width 0.18288)
		(layer "In2.Cu")
		(net "M_B_CPU1_SB_CB<0>")
	)
	(segment
		(start 84.36737 -241.170206)
		(end 83.064096 -241.170206)
		(width 0.088646)
		(layer "In2.Cu")
		(net "M_B_CPU1_SB_CB<0>")
	)
	(segment
		(start 61.951362 -234.120182)
		(end 61.671708 -234.399836)
		(width 0.18288)
		(layer "In2.Cu")
		(net "M_B_CPU1_SB_CB<0>")
	)
	(segment
		(start 63.147194 -234.375452)
		(end 62.891924 -234.120182)
		(width 0.18288)
		(layer "In2.Cu")
		(net "M_B_CPU1_SB_CB<0>")
	)
	(segment
		(start 48.917352 -234.47375)
		(end 48.057308 -234.47375)
		(width 0.18288)
		(layer "In2.Cu")
		(net "M_B_CPU1_SB_CB<0>")
	)
	(segment
		(start 69.201792 -235.237528)
		(end 69.006212 -235.237528)
		(width 0.18288)
		(layer "In2.Cu")
		(net "M_B_CPU1_SB_CB<0>")
	)
	(segment
		(start 69.006212 -235.237528)
		(end 68.221352 -235.561378)
		(width 0.18288)
		(layer "In2.Cu")
		(net "M_B_CPU1_SB_CB<0>")
	)
	(segment
		(start 62.891924 -234.120182)
		(end 61.951362 -234.120182)
		(width 0.18288)
		(layer "In2.Cu")
		(net "M_B_CPU1_SB_CB<0>")
	)
	(segment
		(start 47.82693 -235.373672)
		(end 47.63389 -235.566712)
		(width 0.18288)
		(layer "In2.Cu")
		(net "M_B_CPU1_SB_CB<0>")
	)
	(segment
		(start 54.939184 -233.367326)
		(end 54.746144 -233.560366)
		(width 0.18288)
		(layer "In2.Cu")
		(net "M_B_CPU1_SB_CB<0>")
	)
	(segment
		(start 54.360572 -233.560366)
		(end 54.242716 -233.44251)
		(width 0.18288)
		(layer "In2.Cu")
		(net "M_B_CPU1_SB_CB<0>")
	)
	(arc
		(start 87.958168 -240.991644)
		(mid 87.675466 -240.915868)
		(end 87.392764 -240.991644)
		(width 0.088646)
		(layer "In2.Cu")
		(net "M_B_CPU1_SB_CB<0>")
	)
	(arc
		(start 86.452964 -240.991644)
		(mid 86.265766 -241.041787)
		(end 86.078568 -240.991644)
		(width 0.088646)
		(layer "In2.Cu")
		(net "M_B_CPU1_SB_CB<0>")
	)
	(arc
		(start 87.018368 -240.991644)
		(mid 86.735666 -240.915868)
		(end 86.452964 -240.991644)
		(width 0.088646)
		(layer "In2.Cu")
		(net "M_B_CPU1_SB_CB<0>")
	)
	(arc
		(start 85.138768 -240.991644)
		(mid 84.856066 -240.915868)
		(end 84.573364 -240.991644)
		(width 0.088646)
		(layer "In2.Cu")
		(net "M_B_CPU1_SB_CB<0>")
	)
	(arc
		(start 86.078568 -240.991644)
		(mid 85.795866 -240.915868)
		(end 85.513164 -240.991644)
		(width 0.088646)
		(layer "In2.Cu")
		(net "M_B_CPU1_SB_CB<0>")
	)
	(arc
		(start 85.513164 -240.991644)
		(mid 85.325966 -241.041787)
		(end 85.138768 -240.991644)
		(width 0.088646)
		(layer "In2.Cu")
		(net "M_B_CPU1_SB_CB<0>")
	)
	(arc
		(start 84.573364 -240.991644)
		(mid 84.511886 -241.032646)
		(end 84.45627 -241.081306)
		(width 0.088646)
		(layer "In2.Cu")
		(net "M_B_CPU1_SB_CB<0>")
	)
	(arc
		(start 87.392764 -240.991644)
		(mid 87.205566 -241.041787)
		(end 87.018368 -240.991644)
		(width 0.088646)
		(layer "In2.Cu")
		(net "M_B_CPU1_SB_CB<0>")
	)
	(segment
		(start 39.649908 -247.466612)
		(end 38.315646 -247.466612)
		(width 0.20066)
		(layer "F.Cu")
		(net "M_B_CPU1_SB_CA<6>")
	)
	(segment
		(start 40.520112 -247.523508)
		(end 40.36568 -247.67794)
		(width 0.20066)
		(layer "F.Cu")
		(net "M_B_CPU1_SB_CA<6>")
	)
	(segment
		(start 41.29151 -247.03278)
		(end 40.682672 -247.03278)
		(width 0.20066)
		(layer "F.Cu")
		(net "M_B_CPU1_SB_CA<6>")
	)
	(segment
		(start 45.859446 -247.466612)
		(end 44.22013 -247.466612)
		(width 0.20066)
		(layer "F.Cu")
		(net "M_B_CPU1_SB_CA<6>")
	)
	(segment
		(start 40.520112 -247.19534)
		(end 40.520112 -247.523508)
		(width 0.20066)
		(layer "F.Cu")
		(net "M_B_CPU1_SB_CA<6>")
	)
	(segment
		(start 88.145366 -247.714262)
		(end 88.145366 -247.178322)
		(width 0.20066)
		(layer "F.Cu")
		(net "M_B_CPU1_SB_CA<6>")
	)
	(segment
		(start 44.22013 -247.466612)
		(end 43.795188 -247.04167)
		(width 0.20066)
		(layer "F.Cu")
		(net "M_B_CPU1_SB_CA<6>")
	)
	(segment
		(start 43.616626 -247.04167)
		(end 43.285918 -247.04167)
		(width 0.101854)
		(layer "F.Cu")
		(net "M_B_CPU1_SB_CA<6>")
	)
	(segment
		(start 43.285918 -247.04167)
		(end 41.3004 -247.04167)
		(width 0.1016)
		(layer "F.Cu")
		(net "M_B_CPU1_SB_CA<6>")
	)
	(segment
		(start 40.36568 -247.67794)
		(end 39.861236 -247.67794)
		(width 0.20066)
		(layer "F.Cu")
		(net "M_B_CPU1_SB_CA<6>")
	)
	(segment
		(start 40.682672 -247.03278)
		(end 40.520112 -247.19534)
		(width 0.20066)
		(layer "F.Cu")
		(net "M_B_CPU1_SB_CA<6>")
	)
	(segment
		(start 43.795188 -247.04167)
		(end 43.616626 -247.04167)
		(width 0.20066)
		(layer "F.Cu")
		(net "M_B_CPU1_SB_CA<6>")
	)
	(segment
		(start 41.3004 -247.04167)
		(end 41.29151 -247.03278)
		(width 0.1016)
		(layer "F.Cu")
		(net "M_B_CPU1_SB_CA<6>")
	)
	(segment
		(start 46.964346 -247.466612)
		(end 45.859446 -247.466612)
		(width 0.20066)
		(layer "F.Cu")
		(net "M_B_CPU1_SB_CA<6>")
	)
	(segment
		(start 39.861236 -247.67794)
		(end 39.649908 -247.466612)
		(width 0.20066)
		(layer "F.Cu")
		(net "M_B_CPU1_SB_CA<6>")
	)
	(segment
		(start 72.281034 -248.842276)
		(end 72.087994 -248.649236)
		(width 0.18288)
		(layer "In2.Cu")
		(net "M_B_CPU1_SB_CA<6>")
	)
	(segment
		(start 62.02299 -247.695974)
		(end 61.838078 -247.880886)
		(width 0.18288)
		(layer "In2.Cu")
		(net "M_B_CPU1_SB_CA<6>")
	)
	(segment
		(start 61.838078 -247.880886)
		(end 60.128404 -247.880886)
		(width 0.18288)
		(layer "In2.Cu")
		(net "M_B_CPU1_SB_CA<6>")
	)
	(segment
		(start 60.128404 -247.880886)
		(end 59.985402 -247.737884)
		(width 0.18288)
		(layer "In2.Cu")
		(net "M_B_CPU1_SB_CA<6>")
	)
	(segment
		(start 63.67272 -247.92051)
		(end 63.448184 -247.695974)
		(width 0.18288)
		(layer "In2.Cu")
		(net "M_B_CPU1_SB_CA<6>")
	)
	(segment
		(start 48.353726 -248.987818)
		(end 48.193706 -249.147838)
		(width 0.18288)
		(layer "In2.Cu")
		(net "M_B_CPU1_SB_CA<6>")
	)
	(segment
		(start 88.145366 -247.178322)
		(end 87.649558 -246.929148)
		(width 0.088646)
		(layer "In2.Cu")
		(net "M_B_CPU1_SB_CA<6>")
	)
	(segment
		(start 64.463168 -247.63222)
		(end 64.174878 -247.92051)
		(width 0.18288)
		(layer "In2.Cu")
		(net "M_B_CPU1_SB_CA<6>")
	)
	(segment
		(start 71.894954 -247.926352)
		(end 65.91046 -247.926352)
		(width 0.18288)
		(layer "In2.Cu")
		(net "M_B_CPU1_SB_CA<6>")
	)
	(segment
		(start 51.24704 -247.042686)
		(end 49.646332 -247.042686)
		(width 0.18288)
		(layer "In2.Cu")
		(net "M_B_CPU1_SB_CA<6>")
	)
	(segment
		(start 72.987154 -247.926352)
		(end 72.794114 -248.119392)
		(width 0.18288)
		(layer "In2.Cu")
		(net "M_B_CPU1_SB_CA<6>")
	)
	(segment
		(start 72.794114 -248.649236)
		(end 72.601074 -248.842276)
		(width 0.18288)
		(layer "In2.Cu")
		(net "M_B_CPU1_SB_CA<6>")
	)
	(segment
		(start 63.448184 -247.695974)
		(end 62.02299 -247.695974)
		(width 0.18288)
		(layer "In2.Cu")
		(net "M_B_CPU1_SB_CA<6>")
	)
	(segment
		(start 54.55031 -247.586754)
		(end 54.202076 -247.934988)
		(width 0.18288)
		(layer "In2.Cu")
		(net "M_B_CPU1_SB_CA<6>")
	)
	(segment
		(start 59.985402 -247.737884)
		(end 59.00547 -247.737884)
		(width 0.18288)
		(layer "In2.Cu")
		(net "M_B_CPU1_SB_CA<6>")
	)
	(segment
		(start 49.428654 -247.732042)
		(end 49.241202 -247.919494)
		(width 0.18288)
		(layer "In2.Cu")
		(net "M_B_CPU1_SB_CA<6>")
	)
	(segment
		(start 48.193706 -249.147838)
		(end 47.738538 -249.147838)
		(width 0.18288)
		(layer "In2.Cu")
		(net "M_B_CPU1_SB_CA<6>")
	)
	(segment
		(start 72.087994 -248.649236)
		(end 72.087994 -248.119392)
		(width 0.18288)
		(layer "In2.Cu")
		(net "M_B_CPU1_SB_CA<6>")
	)
	(segment
		(start 47.545498 -248.954798)
		(end 47.545498 -247.659652)
		(width 0.18288)
		(layer "In2.Cu")
		(net "M_B_CPU1_SB_CA<6>")
	)
	(segment
		(start 58.820812 -247.922542)
		(end 55.545736 -247.922542)
		(width 0.18288)
		(layer "In2.Cu")
		(net "M_B_CPU1_SB_CA<6>")
	)
	(segment
		(start 52.620164 -247.934988)
		(end 52.368196 -247.68302)
		(width 0.18288)
		(layer "In2.Cu")
		(net "M_B_CPU1_SB_CA<6>")
	)
	(segment
		(start 83.408774 -246.929656)
		(end 83.389724 -246.910606)
		(width 0.088646)
		(layer "In2.Cu")
		(net "M_B_CPU1_SB_CA<6>")
	)
	(segment
		(start 48.353726 -248.079514)
		(end 48.353726 -248.987818)
		(width 0.18288)
		(layer "In2.Cu")
		(net "M_B_CPU1_SB_CA<6>")
	)
	(segment
		(start 47.738538 -249.147838)
		(end 47.545498 -248.954798)
		(width 0.18288)
		(layer "In2.Cu")
		(net "M_B_CPU1_SB_CA<6>")
	)
	(segment
		(start 49.646332 -247.042686)
		(end 49.428654 -247.260364)
		(width 0.18288)
		(layer "In2.Cu")
		(net "M_B_CPU1_SB_CA<6>")
	)
	(segment
		(start 72.601074 -248.842276)
		(end 72.281034 -248.842276)
		(width 0.18288)
		(layer "In2.Cu")
		(net "M_B_CPU1_SB_CA<6>")
	)
	(segment
		(start 49.241202 -247.919494)
		(end 48.513746 -247.919494)
		(width 0.18288)
		(layer "In2.Cu")
		(net "M_B_CPU1_SB_CA<6>")
	)
	(segment
		(start 47.545498 -247.659652)
		(end 47.352458 -247.466612)
		(width 0.18288)
		(layer "In2.Cu")
		(net "M_B_CPU1_SB_CA<6>")
	)
	(segment
		(start 47.352458 -247.466612)
		(end 46.964346 -247.466612)
		(width 0.18288)
		(layer "In2.Cu")
		(net "M_B_CPU1_SB_CA<6>")
	)
	(segment
		(start 65.616328 -247.63222)
		(end 64.463168 -247.63222)
		(width 0.18288)
		(layer "In2.Cu")
		(net "M_B_CPU1_SB_CA<6>")
	)
	(segment
		(start 48.513746 -247.919494)
		(end 48.353726 -248.079514)
		(width 0.18288)
		(layer "In2.Cu")
		(net "M_B_CPU1_SB_CA<6>")
	)
	(segment
		(start 83.916266 -246.929656)
		(end 83.408774 -246.929656)
		(width 0.088646)
		(layer "In2.Cu")
		(net "M_B_CPU1_SB_CA<6>")
	)
	(segment
		(start 49.428654 -247.260364)
		(end 49.428654 -247.732042)
		(width 0.18288)
		(layer "In2.Cu")
		(net "M_B_CPU1_SB_CA<6>")
	)
	(segment
		(start 52.368196 -247.68302)
		(end 51.887374 -247.68302)
		(width 0.18288)
		(layer "In2.Cu")
		(net "M_B_CPU1_SB_CA<6>")
	)
	(segment
		(start 72.794114 -248.119392)
		(end 72.794114 -248.649236)
		(width 0.18288)
		(layer "In2.Cu")
		(net "M_B_CPU1_SB_CA<6>")
	)
	(segment
		(start 54.202076 -247.934988)
		(end 52.620164 -247.934988)
		(width 0.18288)
		(layer "In2.Cu")
		(net "M_B_CPU1_SB_CA<6>")
	)
	(segment
		(start 83.14055 -246.910606)
		(end 74.619358 -246.910606)
		(width 0.18288)
		(layer "In2.Cu")
		(net "M_B_CPU1_SB_CA<6>")
	)
	(segment
		(start 51.887374 -247.68302)
		(end 51.24704 -247.042686)
		(width 0.18288)
		(layer "In2.Cu")
		(net "M_B_CPU1_SB_CA<6>")
	)
	(segment
		(start 73.603612 -247.926352)
		(end 72.987154 -247.926352)
		(width 0.18288)
		(layer "In2.Cu")
		(net "M_B_CPU1_SB_CA<6>")
	)
	(segment
		(start 65.91046 -247.926352)
		(end 65.616328 -247.63222)
		(width 0.18288)
		(layer "In2.Cu")
		(net "M_B_CPU1_SB_CA<6>")
	)
	(segment
		(start 83.389724 -246.910606)
		(end 83.14055 -246.910606)
		(width 0.088646)
		(layer "In2.Cu")
		(net "M_B_CPU1_SB_CA<6>")
	)
	(segment
		(start 55.545736 -247.922542)
		(end 55.209948 -247.586754)
		(width 0.18288)
		(layer "In2.Cu")
		(net "M_B_CPU1_SB_CA<6>")
	)
	(segment
		(start 64.174878 -247.92051)
		(end 63.67272 -247.92051)
		(width 0.18288)
		(layer "In2.Cu")
		(net "M_B_CPU1_SB_CA<6>")
	)
	(segment
		(start 55.209948 -247.586754)
		(end 54.55031 -247.586754)
		(width 0.18288)
		(layer "In2.Cu")
		(net "M_B_CPU1_SB_CA<6>")
	)
	(segment
		(start 72.087994 -248.119392)
		(end 71.894954 -247.926352)
		(width 0.18288)
		(layer "In2.Cu")
		(net "M_B_CPU1_SB_CA<6>")
	)
	(segment
		(start 59.00547 -247.737884)
		(end 58.820812 -247.922542)
		(width 0.18288)
		(layer "In2.Cu")
		(net "M_B_CPU1_SB_CA<6>")
	)
	(segment
		(start 74.619358 -246.910606)
		(end 73.603612 -247.926352)
		(width 0.18288)
		(layer "In2.Cu")
		(net "M_B_CPU1_SB_CA<6>")
	)
	(arc
		(start 84.573364 -246.853964)
		(mid 84.386166 -246.803821)
		(end 84.198968 -246.853964)
		(width 0.088646)
		(layer "In2.Cu")
		(net "M_B_CPU1_SB_CA<6>")
	)
	(arc
		(start 87.649558 -246.929148)
		(mid 87.516648 -246.906971)
		(end 87.392764 -246.853964)
		(width 0.088646)
		(layer "In2.Cu")
		(net "M_B_CPU1_SB_CA<6>")
	)
	(arc
		(start 87.392764 -246.853964)
		(mid 87.205566 -246.803821)
		(end 87.018368 -246.853964)
		(width 0.088646)
		(layer "In2.Cu")
		(net "M_B_CPU1_SB_CA<6>")
	)
	(arc
		(start 86.078568 -246.853964)
		(mid 85.795866 -246.92974)
		(end 85.513164 -246.853964)
		(width 0.088646)
		(layer "In2.Cu")
		(net "M_B_CPU1_SB_CA<6>")
	)
	(arc
		(start 87.018368 -246.853964)
		(mid 86.735666 -246.92974)
		(end 86.452964 -246.853964)
		(width 0.088646)
		(layer "In2.Cu")
		(net "M_B_CPU1_SB_CA<6>")
	)
	(arc
		(start 85.138768 -246.853964)
		(mid 84.856066 -246.92974)
		(end 84.573364 -246.853964)
		(width 0.088646)
		(layer "In2.Cu")
		(net "M_B_CPU1_SB_CA<6>")
	)
	(arc
		(start 86.452964 -246.853964)
		(mid 86.265766 -246.803821)
		(end 86.078568 -246.853964)
		(width 0.088646)
		(layer "In2.Cu")
		(net "M_B_CPU1_SB_CA<6>")
	)
	(arc
		(start 84.198968 -246.853964)
		(mid 84.062599 -246.910406)
		(end 83.916266 -246.929656)
		(width 0.088646)
		(layer "In2.Cu")
		(net "M_B_CPU1_SB_CA<6>")
	)
	(arc
		(start 85.513164 -246.853964)
		(mid 85.325966 -246.803821)
		(end 85.138768 -246.853964)
		(width 0.088646)
		(layer "In2.Cu")
		(net "M_B_CPU1_SB_CA<6>")
	)
	(segment
		(start 44.987464 -248.741692)
		(end 44.749466 -248.741692)
		(width 0.101854)
		(layer "F.Cu")
		(net "M_B_CPU1_SB_CA<5>")
	)
	(segment
		(start 44.238926 -248.613422)
		(end 44.238926 -248.442734)
		(width 0.20066)
		(layer "F.Cu")
		(net "M_B_CPU1_SB_CA<5>")
	)
	(segment
		(start 44.112942 -248.31675)
		(end 42.415714 -248.31675)
		(width 0.20066)
		(layer "F.Cu")
		(net "M_B_CPU1_SB_CA<5>")
	)
	(segment
		(start 47.753778 -248.592594)
		(end 47.60468 -248.741692)
		(width 0.20066)
		(layer "F.Cu")
		(net "M_B_CPU1_SB_CA<5>")
	)
	(segment
		(start 90.494866 -248.528078)
		(end 90.494612 -248.527824)
		(width 0.20066)
		(layer "F.Cu")
		(net "M_B_CPU1_SB_CA<5>")
	)
	(segment
		(start 48.277526 -248.312432)
		(end 47.882302 -248.312432)
		(width 0.20066)
		(layer "F.Cu")
		(net "M_B_CPU1_SB_CA<5>")
	)
	(segment
		(start 48.935894 -248.524268)
		(end 48.489362 -248.524268)
		(width 0.20066)
		(layer "F.Cu")
		(net "M_B_CPU1_SB_CA<5>")
	)
	(segment
		(start 48.489362 -248.524268)
		(end 48.277526 -248.312432)
		(width 0.20066)
		(layer "F.Cu")
		(net "M_B_CPU1_SB_CA<5>")
	)
	(segment
		(start 49.959514 -248.31675)
		(end 49.143412 -248.31675)
		(width 0.20066)
		(layer "F.Cu")
		(net "M_B_CPU1_SB_CA<5>")
	)
	(segment
		(start 47.753778 -248.440956)
		(end 47.753778 -248.592594)
		(width 0.20066)
		(layer "F.Cu")
		(net "M_B_CPU1_SB_CA<5>")
	)
	(segment
		(start 47.60468 -248.741692)
		(end 47.060358 -248.741692)
		(width 0.20066)
		(layer "F.Cu")
		(net "M_B_CPU1_SB_CA<5>")
	)
	(segment
		(start 44.749466 -248.741692)
		(end 44.735242 -248.755916)
		(width 0.101854)
		(layer "F.Cu")
		(net "M_B_CPU1_SB_CA<5>")
	)
	(segment
		(start 44.238926 -248.442734)
		(end 44.112942 -248.31675)
		(width 0.20066)
		(layer "F.Cu")
		(net "M_B_CPU1_SB_CA<5>")
	)
	(segment
		(start 47.060358 -248.741692)
		(end 44.987464 -248.741692)
		(width 0.1016)
		(layer "F.Cu")
		(net "M_B_CPU1_SB_CA<5>")
	)
	(segment
		(start 90.494612 -248.527824)
		(end 90.494612 -247.992138)
		(width 0.20066)
		(layer "F.Cu")
		(net "M_B_CPU1_SB_CA<5>")
	)
	(segment
		(start 49.143412 -248.31675)
		(end 48.935894 -248.524268)
		(width 0.20066)
		(layer "F.Cu")
		(net "M_B_CPU1_SB_CA<5>")
	)
	(segment
		(start 47.882302 -248.312432)
		(end 47.753778 -248.440956)
		(width 0.20066)
		(layer "F.Cu")
		(net "M_B_CPU1_SB_CA<5>")
	)
	(segment
		(start 44.38142 -248.755916)
		(end 44.238926 -248.613422)
		(width 0.20066)
		(layer "F.Cu")
		(net "M_B_CPU1_SB_CA<5>")
	)
	(segment
		(start 51.064414 -248.31675)
		(end 49.959514 -248.31675)
		(width 0.20066)
		(layer "F.Cu")
		(net "M_B_CPU1_SB_CA<5>")
	)
	(segment
		(start 44.735242 -248.755916)
		(end 44.38142 -248.755916)
		(width 0.20066)
		(layer "F.Cu")
		(net "M_B_CPU1_SB_CA<5>")
	)
	(segment
		(start 90.494612 -247.992138)
		(end 89.97823 -247.603264)
		(width 0.088646)
		(layer "In2.Cu")
		(net "M_B_CPU1_SB_CA<5>")
	)
	(segment
		(start 60.458604 -248.44375)
		(end 59.856116 -249.046238)
		(width 0.18288)
		(layer "In2.Cu")
		(net "M_B_CPU1_SB_CA<5>")
	)
	(segment
		(start 68.83654 -249.386852)
		(end 68.699888 -249.2502)
		(width 0.18288)
		(layer "In2.Cu")
		(net "M_B_CPU1_SB_CA<5>")
	)
	(segment
		(start 55.56885 -248.468642)
		(end 55.011066 -249.026426)
		(width 0.18288)
		(layer "In2.Cu")
		(net "M_B_CPU1_SB_CA<5>")
	)
	(segment
		(start 69.441822 -248.661936)
		(end 69.441822 -249.193812)
		(width 0.18288)
		(layer "In2.Cu")
		(net "M_B_CPU1_SB_CA<5>")
	)
	(segment
		(start 84.342732 -247.70588)
		(end 83.77555 -247.70588)
		(width 0.088646)
		(layer "In2.Cu")
		(net "M_B_CPU1_SB_CA<5>")
	)
	(segment
		(start 62.04839 -248.956576)
		(end 61.535564 -248.44375)
		(width 0.18288)
		(layer "In2.Cu")
		(net "M_B_CPU1_SB_CA<5>")
	)
	(segment
		(start 71.367142 -248.468896)
		(end 71.047102 -248.468896)
		(width 0.18288)
		(layer "In2.Cu")
		(net "M_B_CPU1_SB_CA<5>")
	)
	(segment
		(start 56.98109 -249.101864)
		(end 56.347868 -248.468642)
		(width 0.18288)
		(layer "In2.Cu")
		(net "M_B_CPU1_SB_CA<5>")
	)
	(segment
		(start 87.4014 -247.497854)
		(end 87.392764 -247.50268)
		(width 0.088646)
		(layer "In2.Cu")
		(net "M_B_CPU1_SB_CA<5>")
	)
	(segment
		(start 70.854062 -249.193812)
		(end 70.661022 -249.386852)
		(width 0.18288)
		(layer "In2.Cu")
		(net "M_B_CPU1_SB_CA<5>")
	)
	(segment
		(start 56.347868 -248.468642)
		(end 55.56885 -248.468642)
		(width 0.18288)
		(layer "In2.Cu")
		(net "M_B_CPU1_SB_CA<5>")
	)
	(segment
		(start 62.514734 -248.763536)
		(end 62.321694 -248.956576)
		(width 0.18288)
		(layer "In2.Cu")
		(net "M_B_CPU1_SB_CA<5>")
	)
	(segment
		(start 51.599846 -249.053858)
		(end 51.270662 -248.724674)
		(width 0.18288)
		(layer "In2.Cu")
		(net "M_B_CPU1_SB_CA<5>")
	)
	(segment
		(start 71.560182 -248.661936)
		(end 71.367142 -248.468896)
		(width 0.18288)
		(layer "In2.Cu")
		(net "M_B_CPU1_SB_CA<5>")
	)
	(segment
		(start 63.5381 -248.711212)
		(end 63.34506 -248.518172)
		(width 0.18288)
		(layer "In2.Cu")
		(net "M_B_CPU1_SB_CA<5>")
	)
	(segment
		(start 68.699888 -249.2502)
		(end 68.699888 -248.62917)
		(width 0.18288)
		(layer "In2.Cu")
		(net "M_B_CPU1_SB_CA<5>")
	)
	(segment
		(start 62.514734 -248.393204)
		(end 62.514734 -248.763536)
		(width 0.18288)
		(layer "In2.Cu")
		(net "M_B_CPU1_SB_CA<5>")
	)
	(segment
		(start 52.179728 -249.053858)
		(end 51.599846 -249.053858)
		(width 0.18288)
		(layer "In2.Cu")
		(net "M_B_CPU1_SB_CA<5>")
	)
	(segment
		(start 69.441822 -249.193812)
		(end 69.248782 -249.386852)
		(width 0.18288)
		(layer "In2.Cu")
		(net "M_B_CPU1_SB_CA<5>")
	)
	(segment
		(start 63.34506 -248.400824)
		(end 63.15202 -248.207784)
		(width 0.18288)
		(layer "In2.Cu")
		(net "M_B_CPU1_SB_CA<5>")
	)
	(segment
		(start 72.862186 -249.386852)
		(end 71.753222 -249.386852)
		(width 0.18288)
		(layer "In2.Cu")
		(net "M_B_CPU1_SB_CA<5>")
	)
	(segment
		(start 59.434222 -249.046238)
		(end 59.241182 -248.853198)
		(width 0.18288)
		(layer "In2.Cu")
		(net "M_B_CPU1_SB_CA<5>")
	)
	(segment
		(start 69.248782 -249.386852)
		(end 68.83654 -249.386852)
		(width 0.18288)
		(layer "In2.Cu")
		(net "M_B_CPU1_SB_CA<5>")
	)
	(segment
		(start 70.147942 -249.193812)
		(end 70.147942 -248.661936)
		(width 0.18288)
		(layer "In2.Cu")
		(net "M_B_CPU1_SB_CA<5>")
	)
	(segment
		(start 63.15202 -248.207784)
		(end 62.700154 -248.207784)
		(width 0.18288)
		(layer "In2.Cu")
		(net "M_B_CPU1_SB_CA<5>")
	)
	(segment
		(start 59.120278 -248.51233)
		(end 58.572908 -248.51233)
		(width 0.18288)
		(layer "In2.Cu")
		(net "M_B_CPU1_SB_CA<5>")
	)
	(segment
		(start 87.403432 -247.496584)
		(end 87.4014 -247.497854)
		(width 0.088646)
		(layer "In2.Cu")
		(net "M_B_CPU1_SB_CA<5>")
	)
	(segment
		(start 66.241422 -248.43613)
		(end 65.672208 -249.005344)
		(width 0.18288)
		(layer "In2.Cu")
		(net "M_B_CPU1_SB_CA<5>")
	)
	(segment
		(start 59.241182 -248.633234)
		(end 59.120278 -248.51233)
		(width 0.18288)
		(layer "In2.Cu")
		(net "M_B_CPU1_SB_CA<5>")
	)
	(segment
		(start 83.77555 -247.70588)
		(end 81.885282 -247.70588)
		(width 0.18288)
		(layer "In2.Cu")
		(net "M_B_CPU1_SB_CA<5>")
	)
	(segment
		(start 51.064414 -248.385838)
		(end 51.064414 -248.31675)
		(width 0.18288)
		(layer "In2.Cu")
		(net "M_B_CPU1_SB_CA<5>")
	)
	(segment
		(start 71.560182 -249.193812)
		(end 71.560182 -248.661936)
		(width 0.18288)
		(layer "In2.Cu")
		(net "M_B_CPU1_SB_CA<5>")
	)
	(segment
		(start 64.13246 -248.711212)
		(end 63.5381 -248.711212)
		(width 0.18288)
		(layer "In2.Cu")
		(net "M_B_CPU1_SB_CA<5>")
	)
	(segment
		(start 61.535564 -248.44375)
		(end 60.458604 -248.44375)
		(width 0.18288)
		(layer "In2.Cu")
		(net "M_B_CPU1_SB_CA<5>")
	)
	(segment
		(start 70.340982 -249.386852)
		(end 70.147942 -249.193812)
		(width 0.18288)
		(layer "In2.Cu")
		(net "M_B_CPU1_SB_CA<5>")
	)
	(segment
		(start 70.147942 -248.661936)
		(end 69.954902 -248.468896)
		(width 0.18288)
		(layer "In2.Cu")
		(net "M_B_CPU1_SB_CA<5>")
	)
	(segment
		(start 57.983374 -249.101864)
		(end 56.98109 -249.101864)
		(width 0.18288)
		(layer "In2.Cu")
		(net "M_B_CPU1_SB_CA<5>")
	)
	(segment
		(start 81.885282 -247.70588)
		(end 81.435448 -247.256046)
		(width 0.18288)
		(layer "In2.Cu")
		(net "M_B_CPU1_SB_CA<5>")
	)
	(segment
		(start 69.634862 -248.468896)
		(end 69.441822 -248.661936)
		(width 0.18288)
		(layer "In2.Cu")
		(net "M_B_CPU1_SB_CA<5>")
	)
	(segment
		(start 71.047102 -248.468896)
		(end 70.854062 -248.661936)
		(width 0.18288)
		(layer "In2.Cu")
		(net "M_B_CPU1_SB_CA<5>")
	)
	(segment
		(start 62.321694 -248.956576)
		(end 62.04839 -248.956576)
		(width 0.18288)
		(layer "In2.Cu")
		(net "M_B_CPU1_SB_CA<5>")
	)
	(segment
		(start 52.780184 -248.453402)
		(end 52.179728 -249.053858)
		(width 0.18288)
		(layer "In2.Cu")
		(net "M_B_CPU1_SB_CA<5>")
	)
	(segment
		(start 70.661022 -249.386852)
		(end 70.340982 -249.386852)
		(width 0.18288)
		(layer "In2.Cu")
		(net "M_B_CPU1_SB_CA<5>")
	)
	(segment
		(start 70.854062 -248.661936)
		(end 70.854062 -249.193812)
		(width 0.18288)
		(layer "In2.Cu")
		(net "M_B_CPU1_SB_CA<5>")
	)
	(segment
		(start 59.241182 -248.853198)
		(end 59.241182 -248.633234)
		(width 0.18288)
		(layer "In2.Cu")
		(net "M_B_CPU1_SB_CA<5>")
	)
	(segment
		(start 65.672208 -249.005344)
		(end 64.426592 -249.005344)
		(width 0.18288)
		(layer "In2.Cu")
		(net "M_B_CPU1_SB_CA<5>")
	)
	(segment
		(start 54.526942 -249.026426)
		(end 53.953918 -248.453402)
		(width 0.18288)
		(layer "In2.Cu")
		(net "M_B_CPU1_SB_CA<5>")
	)
	(segment
		(start 68.699888 -248.62917)
		(end 68.506848 -248.43613)
		(width 0.18288)
		(layer "In2.Cu")
		(net "M_B_CPU1_SB_CA<5>")
	)
	(segment
		(start 53.953918 -248.453402)
		(end 52.780184 -248.453402)
		(width 0.18288)
		(layer "In2.Cu")
		(net "M_B_CPU1_SB_CA<5>")
	)
	(segment
		(start 51.270662 -248.592086)
		(end 51.064414 -248.385838)
		(width 0.18288)
		(layer "In2.Cu")
		(net "M_B_CPU1_SB_CA<5>")
	)
	(segment
		(start 51.270662 -248.724674)
		(end 51.270662 -248.592086)
		(width 0.18288)
		(layer "In2.Cu")
		(net "M_B_CPU1_SB_CA<5>")
	)
	(segment
		(start 63.34506 -248.518172)
		(end 63.34506 -248.400824)
		(width 0.18288)
		(layer "In2.Cu")
		(net "M_B_CPU1_SB_CA<5>")
	)
	(segment
		(start 62.700154 -248.207784)
		(end 62.514734 -248.393204)
		(width 0.18288)
		(layer "In2.Cu")
		(net "M_B_CPU1_SB_CA<5>")
	)
	(segment
		(start 71.753222 -249.386852)
		(end 71.560182 -249.193812)
		(width 0.18288)
		(layer "In2.Cu")
		(net "M_B_CPU1_SB_CA<5>")
	)
	(segment
		(start 55.011066 -249.026426)
		(end 54.526942 -249.026426)
		(width 0.18288)
		(layer "In2.Cu")
		(net "M_B_CPU1_SB_CA<5>")
	)
	(segment
		(start 81.435448 -247.256046)
		(end 74.992992 -247.256046)
		(width 0.18288)
		(layer "In2.Cu")
		(net "M_B_CPU1_SB_CA<5>")
	)
	(segment
		(start 74.992992 -247.256046)
		(end 72.862186 -249.386852)
		(width 0.18288)
		(layer "In2.Cu")
		(net "M_B_CPU1_SB_CA<5>")
	)
	(segment
		(start 68.506848 -248.43613)
		(end 66.241422 -248.43613)
		(width 0.18288)
		(layer "In2.Cu")
		(net "M_B_CPU1_SB_CA<5>")
	)
	(segment
		(start 64.426592 -249.005344)
		(end 64.13246 -248.711212)
		(width 0.18288)
		(layer "In2.Cu")
		(net "M_B_CPU1_SB_CA<5>")
	)
	(segment
		(start 88.897714 -247.50268)
		(end 88.8873 -247.496584)
		(width 0.088646)
		(layer "In2.Cu")
		(net "M_B_CPU1_SB_CA<5>")
	)
	(segment
		(start 58.572908 -248.51233)
		(end 57.983374 -249.101864)
		(width 0.18288)
		(layer "In2.Cu")
		(net "M_B_CPU1_SB_CA<5>")
	)
	(segment
		(start 59.856116 -249.046238)
		(end 59.434222 -249.046238)
		(width 0.18288)
		(layer "In2.Cu")
		(net "M_B_CPU1_SB_CA<5>")
	)
	(segment
		(start 84.45627 -247.592342)
		(end 84.342732 -247.70588)
		(width 0.088646)
		(layer "In2.Cu")
		(net "M_B_CPU1_SB_CA<5>")
	)
	(segment
		(start 69.954902 -248.468896)
		(end 69.634862 -248.468896)
		(width 0.18288)
		(layer "In2.Cu")
		(net "M_B_CPU1_SB_CA<5>")
	)
	(arc
		(start 87.018368 -247.50268)
		(mid 86.735666 -247.426904)
		(end 86.452964 -247.50268)
		(width 0.088646)
		(layer "In2.Cu")
		(net "M_B_CPU1_SB_CA<5>")
	)
	(arc
		(start 88.332564 -247.50268)
		(mid 88.145366 -247.552823)
		(end 87.958168 -247.50268)
		(width 0.088646)
		(layer "In2.Cu")
		(net "M_B_CPU1_SB_CA<5>")
	)
	(arc
		(start 89.362026 -247.553226)
		(mid 89.124464 -247.577586)
		(end 88.897714 -247.50268)
		(width 0.088646)
		(layer "In2.Cu")
		(net "M_B_CPU1_SB_CA<5>")
	)
	(arc
		(start 84.573364 -247.50268)
		(mid 84.511886 -247.543682)
		(end 84.45627 -247.592342)
		(width 0.088646)
		(layer "In2.Cu")
		(net "M_B_CPU1_SB_CA<5>")
	)
	(arc
		(start 86.078568 -247.50268)
		(mid 85.795866 -247.426904)
		(end 85.513164 -247.50268)
		(width 0.088646)
		(layer "In2.Cu")
		(net "M_B_CPU1_SB_CA<5>")
	)
	(arc
		(start 85.138768 -247.50268)
		(mid 84.856066 -247.426904)
		(end 84.573364 -247.50268)
		(width 0.088646)
		(layer "In2.Cu")
		(net "M_B_CPU1_SB_CA<5>")
	)
	(arc
		(start 87.392764 -247.50268)
		(mid 87.205566 -247.552823)
		(end 87.018368 -247.50268)
		(width 0.088646)
		(layer "In2.Cu")
		(net "M_B_CPU1_SB_CA<5>")
	)
	(arc
		(start 86.452964 -247.50268)
		(mid 86.265766 -247.552823)
		(end 86.078568 -247.50268)
		(width 0.088646)
		(layer "In2.Cu")
		(net "M_B_CPU1_SB_CA<5>")
	)
	(arc
		(start 85.513164 -247.50268)
		(mid 85.325966 -247.552823)
		(end 85.138768 -247.50268)
		(width 0.088646)
		(layer "In2.Cu")
		(net "M_B_CPU1_SB_CA<5>")
	)
	(arc
		(start 87.958168 -247.50268)
		(mid 87.681609 -247.426937)
		(end 87.403432 -247.496584)
		(width 0.088646)
		(layer "In2.Cu")
		(net "M_B_CPU1_SB_CA<5>")
	)
	(arc
		(start 89.97823 -247.603264)
		(mid 89.67512 -247.516794)
		(end 89.362026 -247.553226)
		(width 0.088646)
		(layer "In2.Cu")
		(net "M_B_CPU1_SB_CA<5>")
	)
	(arc
		(start 88.8873 -247.496584)
		(mid 88.609122 -247.426861)
		(end 88.332564 -247.50268)
		(width 0.088646)
		(layer "In2.Cu")
		(net "M_B_CPU1_SB_CA<5>")
	)
	(segment
		(start 39.861236 -249.377962)
		(end 39.649908 -249.166634)
		(width 0.20066)
		(layer "F.Cu")
		(net "M_B_CPU1_SB_CA<4>")
	)
	(segment
		(start 46.964346 -249.166634)
		(end 45.859446 -249.166634)
		(width 0.20066)
		(layer "F.Cu")
		(net "M_B_CPU1_SB_CA<4>")
	)
	(segment
		(start 43.795188 -248.741692)
		(end 43.616626 -248.741692)
		(width 0.20066)
		(layer "F.Cu")
		(net "M_B_CPU1_SB_CA<4>")
	)
	(segment
		(start 41.3004 -248.741692)
		(end 41.29151 -248.732802)
		(width 0.1016)
		(layer "F.Cu")
		(net "M_B_CPU1_SB_CA<4>")
	)
	(segment
		(start 88.615012 -248.527824)
		(end 88.615012 -247.992138)
		(width 0.20066)
		(layer "F.Cu")
		(net "M_B_CPU1_SB_CA<4>")
	)
	(segment
		(start 88.615266 -248.528078)
		(end 88.615012 -248.527824)
		(width 0.20066)
		(layer "F.Cu")
		(net "M_B_CPU1_SB_CA<4>")
	)
	(segment
		(start 40.520112 -249.22353)
		(end 40.36568 -249.377962)
		(width 0.20066)
		(layer "F.Cu")
		(net "M_B_CPU1_SB_CA<4>")
	)
	(segment
		(start 39.649908 -249.166634)
		(end 38.315646 -249.166634)
		(width 0.20066)
		(layer "F.Cu")
		(net "M_B_CPU1_SB_CA<4>")
	)
	(segment
		(start 44.22013 -249.166634)
		(end 43.795188 -248.741692)
		(width 0.20066)
		(layer "F.Cu")
		(net "M_B_CPU1_SB_CA<4>")
	)
	(segment
		(start 45.859446 -249.166634)
		(end 44.22013 -249.166634)
		(width 0.20066)
		(layer "F.Cu")
		(net "M_B_CPU1_SB_CA<4>")
	)
	(segment
		(start 43.616626 -248.741692)
		(end 43.285918 -248.741692)
		(width 0.101854)
		(layer "F.Cu")
		(net "M_B_CPU1_SB_CA<4>")
	)
	(segment
		(start 40.36568 -249.377962)
		(end 39.861236 -249.377962)
		(width 0.20066)
		(layer "F.Cu")
		(net "M_B_CPU1_SB_CA<4>")
	)
	(segment
		(start 40.682672 -248.732802)
		(end 40.520112 -248.895362)
		(width 0.20066)
		(layer "F.Cu")
		(net "M_B_CPU1_SB_CA<4>")
	)
	(segment
		(start 40.520112 -248.895362)
		(end 40.520112 -249.22353)
		(width 0.20066)
		(layer "F.Cu")
		(net "M_B_CPU1_SB_CA<4>")
	)
	(segment
		(start 43.285918 -248.741692)
		(end 41.3004 -248.741692)
		(width 0.1016)
		(layer "F.Cu")
		(net "M_B_CPU1_SB_CA<4>")
	)
	(segment
		(start 41.29151 -248.732802)
		(end 40.682672 -248.732802)
		(width 0.20066)
		(layer "F.Cu")
		(net "M_B_CPU1_SB_CA<4>")
	)
	(segment
		(start 51.905154 -249.76074)
		(end 51.519582 -249.76074)
		(width 0.18288)
		(layer "In2.Cu")
		(net "M_B_CPU1_SB_CA<4>")
	)
	(segment
		(start 65.834768 -249.526552)
		(end 64.192658 -249.526552)
		(width 0.18288)
		(layer "In2.Cu")
		(net "M_B_CPU1_SB_CA<4>")
	)
	(segment
		(start 54.860698 -249.585988)
		(end 52.079906 -249.585988)
		(width 0.18288)
		(layer "In2.Cu")
		(net "M_B_CPU1_SB_CA<4>")
	)
	(segment
		(start 84.264754 -248.053352)
		(end 83.77555 -248.053352)
		(width 0.088646)
		(layer "In2.Cu")
		(net "M_B_CPU1_SB_CA<4>")
	)
	(segment
		(start 87.89162 -247.684798)
		(end 87.862664 -247.66778)
		(width 0.088646)
		(layer "In2.Cu")
		(net "M_B_CPU1_SB_CA<4>")
	)
	(segment
		(start 51.519582 -249.76074)
		(end 51.350418 -249.591576)
		(width 0.18288)
		(layer "In2.Cu")
		(net "M_B_CPU1_SB_CA<4>")
	)
	(segment
		(start 54.906672 -249.631962)
		(end 54.860698 -249.585988)
		(width 0.18288)
		(layer "In2.Cu")
		(net "M_B_CPU1_SB_CA<4>")
	)
	(segment
		(start 62.700662 -249.579892)
		(end 59.601862 -249.579892)
		(width 0.18288)
		(layer "In2.Cu")
		(net "M_B_CPU1_SB_CA<4>")
	)
	(segment
		(start 50.394108 -249.591576)
		(end 50.2285 -249.425968)
		(width 0.18288)
		(layer "In2.Cu")
		(net "M_B_CPU1_SB_CA<4>")
	)
	(segment
		(start 49.413414 -248.950226)
		(end 49.413414 -249.501152)
		(width 0.18288)
		(layer "In2.Cu")
		(net "M_B_CPU1_SB_CA<4>")
	)
	(segment
		(start 59.549792 -249.631962)
		(end 54.906672 -249.631962)
		(width 0.18288)
		(layer "In2.Cu")
		(net "M_B_CPU1_SB_CA<4>")
	)
	(segment
		(start 73.070466 -249.897392)
		(end 68.413376 -249.897392)
		(width 0.18288)
		(layer "In2.Cu")
		(net "M_B_CPU1_SB_CA<4>")
	)
	(segment
		(start 50.2285 -249.425968)
		(end 50.2285 -248.916952)
		(width 0.18288)
		(layer "In2.Cu")
		(net "M_B_CPU1_SB_CA<4>")
	)
	(segment
		(start 64.192658 -249.526552)
		(end 64.058038 -249.661172)
		(width 0.18288)
		(layer "In2.Cu")
		(net "M_B_CPU1_SB_CA<4>")
	)
	(segment
		(start 88.615012 -247.992138)
		(end 87.89162 -247.684798)
		(width 0.088646)
		(layer "In2.Cu")
		(net "M_B_CPU1_SB_CA<4>")
	)
	(segment
		(start 48.109124 -250.583954)
		(end 47.620936 -250.583954)
		(width 0.18288)
		(layer "In2.Cu")
		(net "M_B_CPU1_SB_CA<4>")
	)
	(segment
		(start 47.480982 -250.444)
		(end 47.480982 -249.68327)
		(width 0.18288)
		(layer "In2.Cu")
		(net "M_B_CPU1_SB_CA<4>")
	)
	(segment
		(start 51.350418 -249.591576)
		(end 50.394108 -249.591576)
		(width 0.18288)
		(layer "In2.Cu")
		(net "M_B_CPU1_SB_CA<4>")
	)
	(segment
		(start 47.480982 -249.68327)
		(end 46.964346 -249.166634)
		(width 0.18288)
		(layer "In2.Cu")
		(net "M_B_CPU1_SB_CA<4>")
	)
	(segment
		(start 63.381382 -249.381772)
		(end 62.898782 -249.381772)
		(width 0.18288)
		(layer "In2.Cu")
		(net "M_B_CPU1_SB_CA<4>")
	)
	(segment
		(start 84.59089 -247.727216)
		(end 84.264754 -248.053352)
		(width 0.088646)
		(layer "In2.Cu")
		(net "M_B_CPU1_SB_CA<4>")
	)
	(segment
		(start 81.362042 -248.053352)
		(end 80.910176 -247.601486)
		(width 0.18288)
		(layer "In2.Cu")
		(net "M_B_CPU1_SB_CA<4>")
	)
	(segment
		(start 49.302416 -249.61215)
		(end 48.478186 -249.61215)
		(width 0.18288)
		(layer "In2.Cu")
		(net "M_B_CPU1_SB_CA<4>")
	)
	(segment
		(start 66.257424 -249.675904)
		(end 65.98412 -249.675904)
		(width 0.18288)
		(layer "In2.Cu")
		(net "M_B_CPU1_SB_CA<4>")
	)
	(segment
		(start 63.660782 -249.661172)
		(end 63.381382 -249.381772)
		(width 0.18288)
		(layer "In2.Cu")
		(net "M_B_CPU1_SB_CA<4>")
	)
	(segment
		(start 50.2285 -248.916952)
		(end 50.06848 -248.756932)
		(width 0.18288)
		(layer "In2.Cu")
		(net "M_B_CPU1_SB_CA<4>")
	)
	(segment
		(start 67.882516 -248.97334)
		(end 66.959988 -248.97334)
		(width 0.18288)
		(layer "In2.Cu")
		(net "M_B_CPU1_SB_CA<4>")
	)
	(segment
		(start 50.06848 -248.756932)
		(end 49.606708 -248.756932)
		(width 0.18288)
		(layer "In2.Cu")
		(net "M_B_CPU1_SB_CA<4>")
	)
	(segment
		(start 75.366372 -247.601486)
		(end 73.070466 -249.897392)
		(width 0.18288)
		(layer "In2.Cu")
		(net "M_B_CPU1_SB_CA<4>")
	)
	(segment
		(start 47.620936 -250.583954)
		(end 47.480982 -250.444)
		(width 0.18288)
		(layer "In2.Cu")
		(net "M_B_CPU1_SB_CA<4>")
	)
	(segment
		(start 59.601862 -249.579892)
		(end 59.549792 -249.631962)
		(width 0.18288)
		(layer "In2.Cu")
		(net "M_B_CPU1_SB_CA<4>")
	)
	(segment
		(start 83.77555 -248.053352)
		(end 81.362042 -248.053352)
		(width 0.18288)
		(layer "In2.Cu")
		(net "M_B_CPU1_SB_CA<4>")
	)
	(segment
		(start 68.149724 -249.240548)
		(end 67.882516 -248.97334)
		(width 0.18288)
		(layer "In2.Cu")
		(net "M_B_CPU1_SB_CA<4>")
	)
	(segment
		(start 65.98412 -249.675904)
		(end 65.834768 -249.526552)
		(width 0.18288)
		(layer "In2.Cu")
		(net "M_B_CPU1_SB_CA<4>")
	)
	(segment
		(start 48.478186 -249.61215)
		(end 48.269144 -249.821192)
		(width 0.18288)
		(layer "In2.Cu")
		(net "M_B_CPU1_SB_CA<4>")
	)
	(segment
		(start 52.079906 -249.585988)
		(end 51.905154 -249.76074)
		(width 0.18288)
		(layer "In2.Cu")
		(net "M_B_CPU1_SB_CA<4>")
	)
	(segment
		(start 48.269144 -250.423934)
		(end 48.109124 -250.583954)
		(width 0.18288)
		(layer "In2.Cu")
		(net "M_B_CPU1_SB_CA<4>")
	)
	(segment
		(start 62.898782 -249.381772)
		(end 62.700662 -249.579892)
		(width 0.18288)
		(layer "In2.Cu")
		(net "M_B_CPU1_SB_CA<4>")
	)
	(segment
		(start 84.59089 -247.726962)
		(end 84.59089 -247.727216)
		(width 0.088646)
		(layer "In2.Cu")
		(net "M_B_CPU1_SB_CA<4>")
	)
	(segment
		(start 64.058038 -249.661172)
		(end 63.660782 -249.661172)
		(width 0.18288)
		(layer "In2.Cu")
		(net "M_B_CPU1_SB_CA<4>")
	)
	(segment
		(start 66.959988 -248.97334)
		(end 66.257424 -249.675904)
		(width 0.18288)
		(layer "In2.Cu")
		(net "M_B_CPU1_SB_CA<4>")
	)
	(segment
		(start 80.910176 -247.601486)
		(end 75.366372 -247.601486)
		(width 0.18288)
		(layer "In2.Cu")
		(net "M_B_CPU1_SB_CA<4>")
	)
	(segment
		(start 48.269144 -249.821192)
		(end 48.269144 -250.423934)
		(width 0.18288)
		(layer "In2.Cu")
		(net "M_B_CPU1_SB_CA<4>")
	)
	(segment
		(start 68.149724 -249.63374)
		(end 68.149724 -249.240548)
		(width 0.18288)
		(layer "In2.Cu")
		(net "M_B_CPU1_SB_CA<4>")
	)
	(segment
		(start 49.413414 -249.501152)
		(end 49.302416 -249.61215)
		(width 0.18288)
		(layer "In2.Cu")
		(net "M_B_CPU1_SB_CA<4>")
	)
	(segment
		(start 49.606708 -248.756932)
		(end 49.413414 -248.950226)
		(width 0.18288)
		(layer "In2.Cu")
		(net "M_B_CPU1_SB_CA<4>")
	)
	(segment
		(start 68.413376 -249.897392)
		(end 68.149724 -249.63374)
		(width 0.18288)
		(layer "In2.Cu")
		(net "M_B_CPU1_SB_CA<4>")
	)
	(arc
		(start 85.983064 -247.66778)
		(mid 85.795866 -247.617637)
		(end 85.608668 -247.66778)
		(width 0.088646)
		(layer "In2.Cu")
		(net "M_B_CPU1_SB_CA<4>")
	)
	(arc
		(start 85.608668 -247.66778)
		(mid 85.325966 -247.743556)
		(end 85.043264 -247.66778)
		(width 0.088646)
		(layer "In2.Cu")
		(net "M_B_CPU1_SB_CA<4>")
	)
	(arc
		(start 86.922864 -247.66778)
		(mid 86.735666 -247.617637)
		(end 86.548468 -247.66778)
		(width 0.088646)
		(layer "In2.Cu")
		(net "M_B_CPU1_SB_CA<4>")
	)
	(arc
		(start 87.862664 -247.66778)
		(mid 87.675466 -247.617603)
		(end 87.488268 -247.66778)
		(width 0.088646)
		(layer "In2.Cu")
		(net "M_B_CPU1_SB_CA<4>")
	)
	(arc
		(start 85.043264 -247.66778)
		(mid 84.856066 -247.617637)
		(end 84.668868 -247.66778)
		(width 0.088646)
		(layer "In2.Cu")
		(net "M_B_CPU1_SB_CA<4>")
	)
	(arc
		(start 84.668868 -247.66778)
		(mid 84.627938 -247.694813)
		(end 84.59089 -247.726962)
		(width 0.088646)
		(layer "In2.Cu")
		(net "M_B_CPU1_SB_CA<4>")
	)
	(arc
		(start 87.488268 -247.66778)
		(mid 87.205566 -247.743556)
		(end 86.922864 -247.66778)
		(width 0.088646)
		(layer "In2.Cu")
		(net "M_B_CPU1_SB_CA<4>")
	)
	(arc
		(start 86.548468 -247.66778)
		(mid 86.265766 -247.743556)
		(end 85.983064 -247.66778)
		(width 0.088646)
		(layer "In2.Cu")
		(net "M_B_CPU1_SB_CA<4>")
	)
	(segment
		(start 47.753778 -250.292616)
		(end 47.60468 -250.441714)
		(width 0.20066)
		(layer "F.Cu")
		(net "M_B_CPU1_SB_CA<3>")
	)
	(segment
		(start 48.277526 -250.012454)
		(end 47.882302 -250.012454)
		(width 0.20066)
		(layer "F.Cu")
		(net "M_B_CPU1_SB_CA<3>")
	)
	(segment
		(start 44.749466 -250.441714)
		(end 44.735242 -250.455938)
		(width 0.101854)
		(layer "F.Cu")
		(net "M_B_CPU1_SB_CA<3>")
	)
	(segment
		(start 90.024966 -249.341894)
		(end 90.024966 -248.806208)
		(width 0.20066)
		(layer "F.Cu")
		(net "M_B_CPU1_SB_CA<3>")
	)
	(segment
		(start 47.060358 -250.441714)
		(end 44.987464 -250.441714)
		(width 0.1016)
		(layer "F.Cu")
		(net "M_B_CPU1_SB_CA<3>")
	)
	(segment
		(start 44.38142 -250.455938)
		(end 44.238926 -250.313444)
		(width 0.20066)
		(layer "F.Cu")
		(net "M_B_CPU1_SB_CA<3>")
	)
	(segment
		(start 44.112942 -250.016772)
		(end 42.415714 -250.016772)
		(width 0.20066)
		(layer "F.Cu")
		(net "M_B_CPU1_SB_CA<3>")
	)
	(segment
		(start 44.238926 -250.313444)
		(end 44.238926 -250.142756)
		(width 0.20066)
		(layer "F.Cu")
		(net "M_B_CPU1_SB_CA<3>")
	)
	(segment
		(start 47.882302 -250.012454)
		(end 47.753778 -250.140978)
		(width 0.20066)
		(layer "F.Cu")
		(net "M_B_CPU1_SB_CA<3>")
	)
	(segment
		(start 44.987464 -250.441714)
		(end 44.749466 -250.441714)
		(width 0.101854)
		(layer "F.Cu")
		(net "M_B_CPU1_SB_CA<3>")
	)
	(segment
		(start 51.064414 -250.016772)
		(end 49.959514 -250.016772)
		(width 0.20066)
		(layer "F.Cu")
		(net "M_B_CPU1_SB_CA<3>")
	)
	(segment
		(start 47.60468 -250.441714)
		(end 47.060358 -250.441714)
		(width 0.20066)
		(layer "F.Cu")
		(net "M_B_CPU1_SB_CA<3>")
	)
	(segment
		(start 48.489362 -250.22429)
		(end 48.277526 -250.012454)
		(width 0.20066)
		(layer "F.Cu")
		(net "M_B_CPU1_SB_CA<3>")
	)
	(segment
		(start 48.935894 -250.22429)
		(end 48.489362 -250.22429)
		(width 0.20066)
		(layer "F.Cu")
		(net "M_B_CPU1_SB_CA<3>")
	)
	(segment
		(start 49.959514 -250.016772)
		(end 49.143412 -250.016772)
		(width 0.20066)
		(layer "F.Cu")
		(net "M_B_CPU1_SB_CA<3>")
	)
	(segment
		(start 49.143412 -250.016772)
		(end 48.935894 -250.22429)
		(width 0.20066)
		(layer "F.Cu")
		(net "M_B_CPU1_SB_CA<3>")
	)
	(segment
		(start 44.735242 -250.455938)
		(end 44.38142 -250.455938)
		(width 0.20066)
		(layer "F.Cu")
		(net "M_B_CPU1_SB_CA<3>")
	)
	(segment
		(start 90.024712 -249.342148)
		(end 90.024966 -249.341894)
		(width 0.20066)
		(layer "F.Cu")
		(net "M_B_CPU1_SB_CA<3>")
	)
	(segment
		(start 47.753778 -250.140978)
		(end 47.753778 -250.292616)
		(width 0.20066)
		(layer "F.Cu")
		(net "M_B_CPU1_SB_CA<3>")
	)
	(segment
		(start 44.238926 -250.142756)
		(end 44.112942 -250.016772)
		(width 0.20066)
		(layer "F.Cu")
		(net "M_B_CPU1_SB_CA<3>")
	)
	(segment
		(start 60.37834 -250.090432)
		(end 60.013596 -250.455176)
		(width 0.18288)
		(layer "In2.Cu")
		(net "M_B_CPU1_SB_CA<3>")
	)
	(segment
		(start 84.779104 -249.075956)
		(end 84.434934 -249.075956)
		(width 0.088646)
		(layer "In2.Cu")
		(net "M_B_CPU1_SB_CA<3>")
	)
	(segment
		(start 67.442334 -249.495818)
		(end 67.169284 -249.495818)
		(width 0.18288)
		(layer "In2.Cu")
		(net "M_B_CPU1_SB_CA<3>")
	)
	(segment
		(start 56.735472 -250.50623)
		(end 56.3753 -250.146058)
		(width 0.18288)
		(layer "In2.Cu")
		(net "M_B_CPU1_SB_CA<3>")
	)
	(segment
		(start 66.656458 -250.410472)
		(end 65.970404 -250.410472)
		(width 0.18288)
		(layer "In2.Cu")
		(net "M_B_CPU1_SB_CA<3>")
	)
	(segment
		(start 85.487764 -248.367296)
		(end 84.779104 -249.075956)
		(width 0.088646)
		(layer "In2.Cu")
		(net "M_B_CPU1_SB_CA<3>")
	)
	(segment
		(start 59.36361 -250.7361)
		(end 59.17057 -250.54306)
		(width 0.18288)
		(layer "In2.Cu")
		(net "M_B_CPU1_SB_CA<3>")
	)
	(segment
		(start 70.798182 -251.453396)
		(end 70.478142 -251.453396)
		(width 0.18288)
		(layer "In2.Cu")
		(net "M_B_CPU1_SB_CA<3>")
	)
	(segment
		(start 61.49975 -250.090432)
		(end 60.37834 -250.090432)
		(width 0.18288)
		(layer "In2.Cu")
		(net "M_B_CPU1_SB_CA<3>")
	)
	(segment
		(start 72.403462 -250.603512)
		(end 72.403462 -251.260356)
		(width 0.18288)
		(layer "In2.Cu")
		(net "M_B_CPU1_SB_CA<3>")
	)
	(segment
		(start 60.013596 -250.455176)
		(end 60.013596 -250.560078)
		(width 0.18288)
		(layer "In2.Cu")
		(net "M_B_CPU1_SB_CA<3>")
	)
	(segment
		(start 52.8193 -250.10999)
		(end 52.262532 -250.666758)
		(width 0.18288)
		(layer "In2.Cu")
		(net "M_B_CPU1_SB_CA<3>")
	)
	(segment
		(start 72.210422 -251.453396)
		(end 71.890382 -251.453396)
		(width 0.18288)
		(layer "In2.Cu")
		(net "M_B_CPU1_SB_CA<3>")
	)
	(segment
		(start 72.403462 -251.260356)
		(end 72.210422 -251.453396)
		(width 0.18288)
		(layer "In2.Cu")
		(net "M_B_CPU1_SB_CA<3>")
	)
	(segment
		(start 85.795866 -248.367296)
		(end 85.487764 -248.367296)
		(width 0.088646)
		(layer "In2.Cu")
		(net "M_B_CPU1_SB_CA<3>")
	)
	(segment
		(start 71.697342 -250.603512)
		(end 71.504302 -250.410472)
		(width 0.18288)
		(layer "In2.Cu")
		(net "M_B_CPU1_SB_CA<3>")
	)
	(segment
		(start 65.970404 -250.410472)
		(end 65.768982 -250.611894)
		(width 0.18288)
		(layer "In2.Cu")
		(net "M_B_CPU1_SB_CA<3>")
	)
	(segment
		(start 73.276968 -250.410472)
		(end 72.596502 -250.410472)
		(width 0.18288)
		(layer "In2.Cu")
		(net "M_B_CPU1_SB_CA<3>")
	)
	(segment
		(start 72.596502 -250.410472)
		(end 72.403462 -250.603512)
		(width 0.18288)
		(layer "In2.Cu")
		(net "M_B_CPU1_SB_CA<3>")
	)
	(segment
		(start 60.013596 -250.560078)
		(end 59.837574 -250.7361)
		(width 0.18288)
		(layer "In2.Cu")
		(net "M_B_CPU1_SB_CA<3>")
	)
	(segment
		(start 67.635374 -249.688858)
		(end 67.442334 -249.495818)
		(width 0.18288)
		(layer "In2.Cu")
		(net "M_B_CPU1_SB_CA<3>")
	)
	(segment
		(start 51.7144 -250.666758)
		(end 51.064414 -250.016772)
		(width 0.18288)
		(layer "In2.Cu")
		(net "M_B_CPU1_SB_CA<3>")
	)
	(segment
		(start 58.984896 -250.146566)
		(end 58.632598 -250.146566)
		(width 0.18288)
		(layer "In2.Cu")
		(net "M_B_CPU1_SB_CA<3>")
	)
	(segment
		(start 71.184262 -250.410472)
		(end 70.991222 -250.603512)
		(width 0.18288)
		(layer "In2.Cu")
		(net "M_B_CPU1_SB_CA<3>")
	)
	(segment
		(start 54.416198 -250.56846)
		(end 53.957728 -250.10999)
		(width 0.18288)
		(layer "In2.Cu")
		(net "M_B_CPU1_SB_CA<3>")
	)
	(segment
		(start 80.509872 -247.946926)
		(end 75.740514 -247.946926)
		(width 0.18288)
		(layer "In2.Cu")
		(net "M_B_CPU1_SB_CA<3>")
	)
	(segment
		(start 66.849498 -249.815604)
		(end 66.849498 -250.217432)
		(width 0.18288)
		(layer "In2.Cu")
		(net "M_B_CPU1_SB_CA<3>")
	)
	(segment
		(start 53.957728 -250.10999)
		(end 52.8193 -250.10999)
		(width 0.18288)
		(layer "In2.Cu")
		(net "M_B_CPU1_SB_CA<3>")
	)
	(segment
		(start 56.3753 -250.146058)
		(end 55.276496 -250.146058)
		(width 0.18288)
		(layer "In2.Cu")
		(net "M_B_CPU1_SB_CA<3>")
	)
	(segment
		(start 52.262532 -250.666758)
		(end 51.7144 -250.666758)
		(width 0.18288)
		(layer "In2.Cu")
		(net "M_B_CPU1_SB_CA<3>")
	)
	(segment
		(start 89.367868 -248.31675)
		(end 89.367106 -248.316496)
		(width 0.088646)
		(layer "In2.Cu")
		(net "M_B_CPU1_SB_CA<3>")
	)
	(segment
		(start 71.890382 -251.453396)
		(end 71.697342 -251.260356)
		(width 0.18288)
		(layer "In2.Cu")
		(net "M_B_CPU1_SB_CA<3>")
	)
	(segment
		(start 70.991222 -250.603512)
		(end 70.991222 -251.260356)
		(width 0.18288)
		(layer "In2.Cu")
		(net "M_B_CPU1_SB_CA<3>")
	)
	(segment
		(start 71.504302 -250.410472)
		(end 71.184262 -250.410472)
		(width 0.18288)
		(layer "In2.Cu")
		(net "M_B_CPU1_SB_CA<3>")
	)
	(segment
		(start 59.17057 -250.54306)
		(end 59.17057 -250.33224)
		(width 0.18288)
		(layer "In2.Cu")
		(net "M_B_CPU1_SB_CA<3>")
	)
	(segment
		(start 65.768982 -250.611894)
		(end 64.308228 -250.611894)
		(width 0.18288)
		(layer "In2.Cu")
		(net "M_B_CPU1_SB_CA<3>")
	)
	(segment
		(start 75.740514 -247.946926)
		(end 73.276968 -250.410472)
		(width 0.18288)
		(layer "In2.Cu")
		(net "M_B_CPU1_SB_CA<3>")
	)
	(segment
		(start 58.272934 -250.50623)
		(end 56.735472 -250.50623)
		(width 0.18288)
		(layer "In2.Cu")
		(net "M_B_CPU1_SB_CA<3>")
	)
	(segment
		(start 59.17057 -250.33224)
		(end 58.984896 -250.146566)
		(width 0.18288)
		(layer "In2.Cu")
		(net "M_B_CPU1_SB_CA<3>")
	)
	(segment
		(start 88.427814 -248.316496)
		(end 88.4174 -248.3104)
		(width 0.088646)
		(layer "In2.Cu")
		(net "M_B_CPU1_SB_CA<3>")
	)
	(segment
		(start 90.024966 -248.806208)
		(end 89.396824 -248.33326)
		(width 0.088646)
		(layer "In2.Cu")
		(net "M_B_CPU1_SB_CA<3>")
	)
	(segment
		(start 67.169284 -249.495818)
		(end 66.849498 -249.815604)
		(width 0.18288)
		(layer "In2.Cu")
		(net "M_B_CPU1_SB_CA<3>")
	)
	(segment
		(start 81.638902 -249.075956)
		(end 80.509872 -247.946926)
		(width 0.18288)
		(layer "In2.Cu")
		(net "M_B_CPU1_SB_CA<3>")
	)
	(segment
		(start 67.897502 -250.410472)
		(end 67.635374 -250.148344)
		(width 0.18288)
		(layer "In2.Cu")
		(net "M_B_CPU1_SB_CA<3>")
	)
	(segment
		(start 67.635374 -250.148344)
		(end 67.635374 -249.688858)
		(width 0.18288)
		(layer "In2.Cu")
		(net "M_B_CPU1_SB_CA<3>")
	)
	(segment
		(start 84.434934 -249.075956)
		(end 81.638902 -249.075956)
		(width 0.18288)
		(layer "In2.Cu")
		(net "M_B_CPU1_SB_CA<3>")
	)
	(segment
		(start 70.285102 -250.603512)
		(end 70.092062 -250.410472)
		(width 0.18288)
		(layer "In2.Cu")
		(net "M_B_CPU1_SB_CA<3>")
	)
	(segment
		(start 89.396824 -248.33326)
		(end 89.367868 -248.31675)
		(width 0.088646)
		(layer "In2.Cu")
		(net "M_B_CPU1_SB_CA<3>")
	)
	(segment
		(start 55.276496 -250.146058)
		(end 54.854094 -250.56846)
		(width 0.18288)
		(layer "In2.Cu")
		(net "M_B_CPU1_SB_CA<3>")
	)
	(segment
		(start 70.478142 -251.453396)
		(end 70.285102 -251.260356)
		(width 0.18288)
		(layer "In2.Cu")
		(net "M_B_CPU1_SB_CA<3>")
	)
	(segment
		(start 62.713616 -250.224544)
		(end 62.435232 -250.502928)
		(width 0.18288)
		(layer "In2.Cu")
		(net "M_B_CPU1_SB_CA<3>")
	)
	(segment
		(start 63.920878 -250.224544)
		(end 62.713616 -250.224544)
		(width 0.18288)
		(layer "In2.Cu")
		(net "M_B_CPU1_SB_CA<3>")
	)
	(segment
		(start 66.849498 -250.217432)
		(end 66.656458 -250.410472)
		(width 0.18288)
		(layer "In2.Cu")
		(net "M_B_CPU1_SB_CA<3>")
	)
	(segment
		(start 64.308228 -250.611894)
		(end 63.920878 -250.224544)
		(width 0.18288)
		(layer "In2.Cu")
		(net "M_B_CPU1_SB_CA<3>")
	)
	(segment
		(start 88.428068 -248.316496)
		(end 88.427814 -248.316496)
		(width 0.088646)
		(layer "In2.Cu")
		(net "M_B_CPU1_SB_CA<3>")
	)
	(segment
		(start 70.092062 -250.410472)
		(end 67.897502 -250.410472)
		(width 0.18288)
		(layer "In2.Cu")
		(net "M_B_CPU1_SB_CA<3>")
	)
	(segment
		(start 70.991222 -251.260356)
		(end 70.798182 -251.453396)
		(width 0.18288)
		(layer "In2.Cu")
		(net "M_B_CPU1_SB_CA<3>")
	)
	(segment
		(start 62.435232 -250.502928)
		(end 61.912246 -250.502928)
		(width 0.18288)
		(layer "In2.Cu")
		(net "M_B_CPU1_SB_CA<3>")
	)
	(segment
		(start 70.285102 -251.260356)
		(end 70.285102 -250.603512)
		(width 0.18288)
		(layer "In2.Cu")
		(net "M_B_CPU1_SB_CA<3>")
	)
	(segment
		(start 61.912246 -250.502928)
		(end 61.49975 -250.090432)
		(width 0.18288)
		(layer "In2.Cu")
		(net "M_B_CPU1_SB_CA<3>")
	)
	(segment
		(start 54.854094 -250.56846)
		(end 54.416198 -250.56846)
		(width 0.18288)
		(layer "In2.Cu")
		(net "M_B_CPU1_SB_CA<3>")
	)
	(segment
		(start 71.697342 -251.260356)
		(end 71.697342 -250.603512)
		(width 0.18288)
		(layer "In2.Cu")
		(net "M_B_CPU1_SB_CA<3>")
	)
	(segment
		(start 59.837574 -250.7361)
		(end 59.36361 -250.7361)
		(width 0.18288)
		(layer "In2.Cu")
		(net "M_B_CPU1_SB_CA<3>")
	)
	(segment
		(start 58.632598 -250.146566)
		(end 58.272934 -250.50623)
		(width 0.18288)
		(layer "In2.Cu")
		(net "M_B_CPU1_SB_CA<3>")
	)
	(arc
		(start 89.367106 -248.316496)
		(mid 89.084658 -248.240813)
		(end 88.80221 -248.316496)
		(width 0.088646)
		(layer "In2.Cu")
		(net "M_B_CPU1_SB_CA<3>")
	)
	(arc
		(start 88.4174 -248.3104)
		(mid 88.139222 -248.240708)
		(end 87.862664 -248.316496)
		(width 0.088646)
		(layer "In2.Cu")
		(net "M_B_CPU1_SB_CA<3>")
	)
	(arc
		(start 88.80221 -248.316496)
		(mid 88.615156 -248.366546)
		(end 88.428068 -248.316496)
		(width 0.088646)
		(layer "In2.Cu")
		(net "M_B_CPU1_SB_CA<3>")
	)
	(arc
		(start 87.862664 -248.316496)
		(mid 87.675466 -248.366639)
		(end 87.488268 -248.316496)
		(width 0.088646)
		(layer "In2.Cu")
		(net "M_B_CPU1_SB_CA<3>")
	)
	(arc
		(start 86.548468 -248.316496)
		(mid 86.265766 -248.240754)
		(end 85.983064 -248.316496)
		(width 0.088646)
		(layer "In2.Cu")
		(net "M_B_CPU1_SB_CA<3>")
	)
	(arc
		(start 86.922864 -248.316496)
		(mid 86.735666 -248.366639)
		(end 86.548468 -248.316496)
		(width 0.088646)
		(layer "In2.Cu")
		(net "M_B_CPU1_SB_CA<3>")
	)
	(arc
		(start 87.488268 -248.316496)
		(mid 87.205566 -248.240754)
		(end 86.922864 -248.316496)
		(width 0.088646)
		(layer "In2.Cu")
		(net "M_B_CPU1_SB_CA<3>")
	)
	(arc
		(start 85.983064 -248.316496)
		(mid 85.892808 -248.354218)
		(end 85.795866 -248.367296)
		(width 0.088646)
		(layer "In2.Cu")
		(net "M_B_CPU1_SB_CA<3>")
	)
	(segment
		(start 40.520112 -250.923552)
		(end 40.36568 -251.077984)
		(width 0.20066)
		(layer "F.Cu")
		(net "M_B_CPU1_SB_CA<2>")
	)
	(segment
		(start 89.084912 -249.342148)
		(end 89.085166 -249.341894)
		(width 0.20066)
		(layer "F.Cu")
		(net "M_B_CPU1_SB_CA<2>")
	)
	(segment
		(start 43.285918 -250.441714)
		(end 41.3004 -250.441714)
		(width 0.1016)
		(layer "F.Cu")
		(net "M_B_CPU1_SB_CA<2>")
	)
	(segment
		(start 46.964346 -250.866656)
		(end 45.859446 -250.866656)
		(width 0.20066)
		(layer "F.Cu")
		(net "M_B_CPU1_SB_CA<2>")
	)
	(segment
		(start 39.861236 -251.077984)
		(end 39.649908 -250.866656)
		(width 0.20066)
		(layer "F.Cu")
		(net "M_B_CPU1_SB_CA<2>")
	)
	(segment
		(start 45.859446 -250.866656)
		(end 44.22013 -250.866656)
		(width 0.20066)
		(layer "F.Cu")
		(net "M_B_CPU1_SB_CA<2>")
	)
	(segment
		(start 43.616626 -250.441714)
		(end 43.285918 -250.441714)
		(width 0.101854)
		(layer "F.Cu")
		(net "M_B_CPU1_SB_CA<2>")
	)
	(segment
		(start 40.682672 -250.432824)
		(end 40.520112 -250.595384)
		(width 0.20066)
		(layer "F.Cu")
		(net "M_B_CPU1_SB_CA<2>")
	)
	(segment
		(start 40.36568 -251.077984)
		(end 39.861236 -251.077984)
		(width 0.20066)
		(layer "F.Cu")
		(net "M_B_CPU1_SB_CA<2>")
	)
	(segment
		(start 44.22013 -250.866656)
		(end 43.795188 -250.441714)
		(width 0.20066)
		(layer "F.Cu")
		(net "M_B_CPU1_SB_CA<2>")
	)
	(segment
		(start 89.085166 -249.341894)
		(end 89.085166 -248.806208)
		(width 0.20066)
		(layer "F.Cu")
		(net "M_B_CPU1_SB_CA<2>")
	)
	(segment
		(start 41.3004 -250.441714)
		(end 41.29151 -250.432824)
		(width 0.1016)
		(layer "F.Cu")
		(net "M_B_CPU1_SB_CA<2>")
	)
	(segment
		(start 41.29151 -250.432824)
		(end 40.682672 -250.432824)
		(width 0.20066)
		(layer "F.Cu")
		(net "M_B_CPU1_SB_CA<2>")
	)
	(segment
		(start 39.649908 -250.866656)
		(end 38.315646 -250.866656)
		(width 0.20066)
		(layer "F.Cu")
		(net "M_B_CPU1_SB_CA<2>")
	)
	(segment
		(start 40.520112 -250.595384)
		(end 40.520112 -250.923552)
		(width 0.20066)
		(layer "F.Cu")
		(net "M_B_CPU1_SB_CA<2>")
	)
	(segment
		(start 43.795188 -250.441714)
		(end 43.616626 -250.441714)
		(width 0.20066)
		(layer "F.Cu")
		(net "M_B_CPU1_SB_CA<2>")
	)
	(segment
		(start 69.882258 -251.99975)
		(end 69.689218 -251.80671)
		(width 0.18288)
		(layer "In2.Cu")
		(net "M_B_CPU1_SB_CA<2>")
	)
	(segment
		(start 85.795866 -248.557542)
		(end 85.602318 -248.557542)
		(width 0.088646)
		(layer "In2.Cu")
		(net "M_B_CPU1_SB_CA<2>")
	)
	(segment
		(start 89.085166 -248.806208)
		(end 88.362536 -248.499122)
		(width 0.088646)
		(layer "In2.Cu")
		(net "M_B_CPU1_SB_CA<2>")
	)
	(segment
		(start 64.344042 -251.12599)
		(end 64.125856 -251.344176)
		(width 0.18288)
		(layer "In2.Cu")
		(net "M_B_CPU1_SB_CA<2>")
	)
	(segment
		(start 88.362536 -248.499122)
		(end 88.332564 -248.481596)
		(width 0.088646)
		(layer "In2.Cu")
		(net "M_B_CPU1_SB_CA<2>")
	)
	(segment
		(start 58.93816 -251.259594)
		(end 58.892186 -251.305568)
		(width 0.18288)
		(layer "In2.Cu")
		(net "M_B_CPU1_SB_CA<2>")
	)
	(segment
		(start 63.399162 -251.014738)
		(end 62.1792 -251.014738)
		(width 0.18288)
		(layer "In2.Cu")
		(net "M_B_CPU1_SB_CA<2>")
	)
	(segment
		(start 65.791842 -251.12599)
		(end 64.344042 -251.12599)
		(width 0.18288)
		(layer "In2.Cu")
		(net "M_B_CPU1_SB_CA<2>")
	)
	(segment
		(start 57.870598 -251.017278)
		(end 56.87695 -251.017278)
		(width 0.18288)
		(layer "In2.Cu")
		(net "M_B_CPU1_SB_CA<2>")
	)
	(segment
		(start 80.027272 -248.292366)
		(end 76.119482 -248.292366)
		(width 0.18288)
		(layer "In2.Cu")
		(net "M_B_CPU1_SB_CA<2>")
	)
	(segment
		(start 62.1792 -251.014738)
		(end 61.934344 -251.259594)
		(width 0.18288)
		(layer "In2.Cu")
		(net "M_B_CPU1_SB_CA<2>")
	)
	(segment
		(start 58.158888 -251.305568)
		(end 57.870598 -251.017278)
		(width 0.18288)
		(layer "In2.Cu")
		(net "M_B_CPU1_SB_CA<2>")
	)
	(segment
		(start 48.827436 -251.845826)
		(end 48.634396 -252.038866)
		(width 0.18288)
		(layer "In2.Cu")
		(net "M_B_CPU1_SB_CA<2>")
	)
	(segment
		(start 55.172864 -251.08916)
		(end 54.422294 -251.08916)
		(width 0.18288)
		(layer "In2.Cu")
		(net "M_B_CPU1_SB_CA<2>")
	)
	(segment
		(start 52.534058 -251.337572)
		(end 52.375308 -251.178822)
		(width 0.18288)
		(layer "In2.Cu")
		(net "M_B_CPU1_SB_CA<2>")
	)
	(segment
		(start 47.844456 -251.845826)
		(end 47.844456 -251.544074)
		(width 0.18288)
		(layer "In2.Cu")
		(net "M_B_CPU1_SB_CA<2>")
	)
	(segment
		(start 58.892186 -251.305568)
		(end 58.158888 -251.305568)
		(width 0.18288)
		(layer "In2.Cu")
		(net "M_B_CPU1_SB_CA<2>")
	)
	(segment
		(start 84.738464 -249.421396)
		(end 84.434934 -249.421396)
		(width 0.088646)
		(layer "In2.Cu")
		(net "M_B_CPU1_SB_CA<2>")
	)
	(segment
		(start 51.933856 -251.291598)
		(end 49.020984 -251.291598)
		(width 0.18288)
		(layer "In2.Cu")
		(net "M_B_CPU1_SB_CA<2>")
	)
	(segment
		(start 69.689218 -251.80671)
		(end 69.689218 -251.170948)
		(width 0.18288)
		(layer "In2.Cu")
		(net "M_B_CPU1_SB_CA<2>")
	)
	(segment
		(start 47.844456 -251.544074)
		(end 47.651416 -251.351034)
		(width 0.18288)
		(layer "In2.Cu")
		(net "M_B_CPU1_SB_CA<2>")
	)
	(segment
		(start 52.375308 -251.178822)
		(end 52.046632 -251.178822)
		(width 0.18288)
		(layer "In2.Cu")
		(net "M_B_CPU1_SB_CA<2>")
	)
	(segment
		(start 52.046632 -251.178822)
		(end 51.933856 -251.291598)
		(width 0.18288)
		(layer "In2.Cu")
		(net "M_B_CPU1_SB_CA<2>")
	)
	(segment
		(start 64.125856 -251.344176)
		(end 63.7286 -251.344176)
		(width 0.18288)
		(layer "In2.Cu")
		(net "M_B_CPU1_SB_CA<2>")
	)
	(segment
		(start 49.020984 -251.291598)
		(end 48.827436 -251.485146)
		(width 0.18288)
		(layer "In2.Cu")
		(net "M_B_CPU1_SB_CA<2>")
	)
	(segment
		(start 48.037496 -252.038866)
		(end 47.844456 -251.845826)
		(width 0.18288)
		(layer "In2.Cu")
		(net "M_B_CPU1_SB_CA<2>")
	)
	(segment
		(start 61.934344 -251.259594)
		(end 58.93816 -251.259594)
		(width 0.18288)
		(layer "In2.Cu")
		(net "M_B_CPU1_SB_CA<2>")
	)
	(segment
		(start 54.422294 -251.08916)
		(end 54.173882 -251.337572)
		(width 0.18288)
		(layer "In2.Cu")
		(net "M_B_CPU1_SB_CA<2>")
	)
	(segment
		(start 72.412098 -251.99975)
		(end 69.882258 -251.99975)
		(width 0.18288)
		(layer "In2.Cu")
		(net "M_B_CPU1_SB_CA<2>")
	)
	(segment
		(start 56.87695 -251.017278)
		(end 56.594248 -251.29998)
		(width 0.18288)
		(layer "In2.Cu")
		(net "M_B_CPU1_SB_CA<2>")
	)
	(segment
		(start 88.332564 -248.481596)
		(end 88.332564 -248.48185)
		(width 0.088646)
		(layer "In2.Cu")
		(net "M_B_CPU1_SB_CA<2>")
	)
	(segment
		(start 69.689218 -251.170948)
		(end 69.496178 -250.977908)
		(width 0.18288)
		(layer "In2.Cu")
		(net "M_B_CPU1_SB_CA<2>")
	)
	(segment
		(start 85.602318 -248.557542)
		(end 84.738464 -249.421396)
		(width 0.088646)
		(layer "In2.Cu")
		(net "M_B_CPU1_SB_CA<2>")
	)
	(segment
		(start 63.7286 -251.344176)
		(end 63.399162 -251.014738)
		(width 0.18288)
		(layer "In2.Cu")
		(net "M_B_CPU1_SB_CA<2>")
	)
	(segment
		(start 48.827436 -251.485146)
		(end 48.827436 -251.845826)
		(width 0.18288)
		(layer "In2.Cu")
		(net "M_B_CPU1_SB_CA<2>")
	)
	(segment
		(start 81.156302 -249.421396)
		(end 80.027272 -248.292366)
		(width 0.18288)
		(layer "In2.Cu")
		(net "M_B_CPU1_SB_CA<2>")
	)
	(segment
		(start 76.119482 -248.292366)
		(end 72.412098 -251.99975)
		(width 0.18288)
		(layer "In2.Cu")
		(net "M_B_CPU1_SB_CA<2>")
	)
	(segment
		(start 84.434934 -249.421396)
		(end 81.156302 -249.421396)
		(width 0.18288)
		(layer "In2.Cu")
		(net "M_B_CPU1_SB_CA<2>")
	)
	(segment
		(start 47.448724 -251.351034)
		(end 46.964346 -250.866656)
		(width 0.18288)
		(layer "In2.Cu")
		(net "M_B_CPU1_SB_CA<2>")
	)
	(segment
		(start 66.890392 -250.977908)
		(end 66.421254 -251.447046)
		(width 0.18288)
		(layer "In2.Cu")
		(net "M_B_CPU1_SB_CA<2>")
	)
	(segment
		(start 47.651416 -251.351034)
		(end 47.448724 -251.351034)
		(width 0.18288)
		(layer "In2.Cu")
		(net "M_B_CPU1_SB_CA<2>")
	)
	(segment
		(start 48.634396 -252.038866)
		(end 48.037496 -252.038866)
		(width 0.18288)
		(layer "In2.Cu")
		(net "M_B_CPU1_SB_CA<2>")
	)
	(segment
		(start 69.496178 -250.977908)
		(end 66.890392 -250.977908)
		(width 0.18288)
		(layer "In2.Cu")
		(net "M_B_CPU1_SB_CA<2>")
	)
	(segment
		(start 56.594248 -251.29998)
		(end 55.383684 -251.29998)
		(width 0.18288)
		(layer "In2.Cu")
		(net "M_B_CPU1_SB_CA<2>")
	)
	(segment
		(start 66.421254 -251.447046)
		(end 66.112898 -251.447046)
		(width 0.18288)
		(layer "In2.Cu")
		(net "M_B_CPU1_SB_CA<2>")
	)
	(segment
		(start 55.383684 -251.29998)
		(end 55.172864 -251.08916)
		(width 0.18288)
		(layer "In2.Cu")
		(net "M_B_CPU1_SB_CA<2>")
	)
	(segment
		(start 66.112898 -251.447046)
		(end 65.791842 -251.12599)
		(width 0.18288)
		(layer "In2.Cu")
		(net "M_B_CPU1_SB_CA<2>")
	)
	(segment
		(start 54.173882 -251.337572)
		(end 52.534058 -251.337572)
		(width 0.18288)
		(layer "In2.Cu")
		(net "M_B_CPU1_SB_CA<2>")
	)
	(arc
		(start 87.958168 -248.48185)
		(mid 87.675466 -248.557592)
		(end 87.392764 -248.48185)
		(width 0.088646)
		(layer "In2.Cu")
		(net "M_B_CPU1_SB_CA<2>")
	)
	(arc
		(start 87.018368 -248.48185)
		(mid 86.735666 -248.557592)
		(end 86.452964 -248.48185)
		(width 0.088646)
		(layer "In2.Cu")
		(net "M_B_CPU1_SB_CA<2>")
	)
	(arc
		(start 88.332564 -248.48185)
		(mid 88.145366 -248.431707)
		(end 87.958168 -248.48185)
		(width 0.088646)
		(layer "In2.Cu")
		(net "M_B_CPU1_SB_CA<2>")
	)
	(arc
		(start 86.078568 -248.48185)
		(mid 85.942202 -248.538328)
		(end 85.795866 -248.557542)
		(width 0.088646)
		(layer "In2.Cu")
		(net "M_B_CPU1_SB_CA<2>")
	)
	(arc
		(start 86.452964 -248.48185)
		(mid 86.265766 -248.431707)
		(end 86.078568 -248.48185)
		(width 0.088646)
		(layer "In2.Cu")
		(net "M_B_CPU1_SB_CA<2>")
	)
	(arc
		(start 87.392764 -248.48185)
		(mid 87.205566 -248.431707)
		(end 87.018368 -248.48185)
		(width 0.088646)
		(layer "In2.Cu")
		(net "M_B_CPU1_SB_CA<2>")
	)
	(segment
		(start 49.959514 -251.716794)
		(end 49.143412 -251.716794)
		(width 0.20066)
		(layer "F.Cu")
		(net "M_B_CPU1_SB_CA<1>")
	)
	(segment
		(start 47.060358 -252.141736)
		(end 44.987464 -252.141736)
		(width 0.1016)
		(layer "F.Cu")
		(net "M_B_CPU1_SB_CA<1>")
	)
	(segment
		(start 49.143412 -251.716794)
		(end 48.935894 -251.924312)
		(width 0.20066)
		(layer "F.Cu")
		(net "M_B_CPU1_SB_CA<1>")
	)
	(segment
		(start 44.238926 -252.013466)
		(end 44.238926 -251.842778)
		(width 0.20066)
		(layer "F.Cu")
		(net "M_B_CPU1_SB_CA<1>")
	)
	(segment
		(start 92.374466 -248.528078)
		(end 92.374212 -248.527824)
		(width 0.20066)
		(layer "F.Cu")
		(net "M_B_CPU1_SB_CA<1>")
	)
	(segment
		(start 44.749466 -252.141736)
		(end 44.735242 -252.15596)
		(width 0.101854)
		(layer "F.Cu")
		(net "M_B_CPU1_SB_CA<1>")
	)
	(segment
		(start 48.489362 -251.924312)
		(end 48.277526 -251.712476)
		(width 0.20066)
		(layer "F.Cu")
		(net "M_B_CPU1_SB_CA<1>")
	)
	(segment
		(start 47.753778 -251.992638)
		(end 47.60468 -252.141736)
		(width 0.20066)
		(layer "F.Cu")
		(net "M_B_CPU1_SB_CA<1>")
	)
	(segment
		(start 44.238926 -251.842778)
		(end 44.112942 -251.716794)
		(width 0.20066)
		(layer "F.Cu")
		(net "M_B_CPU1_SB_CA<1>")
	)
	(segment
		(start 47.753778 -251.841)
		(end 47.753778 -251.992638)
		(width 0.20066)
		(layer "F.Cu")
		(net "M_B_CPU1_SB_CA<1>")
	)
	(segment
		(start 44.38142 -252.15596)
		(end 44.238926 -252.013466)
		(width 0.20066)
		(layer "F.Cu")
		(net "M_B_CPU1_SB_CA<1>")
	)
	(segment
		(start 48.935894 -251.924312)
		(end 48.489362 -251.924312)
		(width 0.20066)
		(layer "F.Cu")
		(net "M_B_CPU1_SB_CA<1>")
	)
	(segment
		(start 47.60468 -252.141736)
		(end 47.060358 -252.141736)
		(width 0.20066)
		(layer "F.Cu")
		(net "M_B_CPU1_SB_CA<1>")
	)
	(segment
		(start 44.735242 -252.15596)
		(end 44.38142 -252.15596)
		(width 0.20066)
		(layer "F.Cu")
		(net "M_B_CPU1_SB_CA<1>")
	)
	(segment
		(start 48.277526 -251.712476)
		(end 47.882302 -251.712476)
		(width 0.20066)
		(layer "F.Cu")
		(net "M_B_CPU1_SB_CA<1>")
	)
	(segment
		(start 44.112942 -251.716794)
		(end 42.415714 -251.716794)
		(width 0.20066)
		(layer "F.Cu")
		(net "M_B_CPU1_SB_CA<1>")
	)
	(segment
		(start 44.987464 -252.141736)
		(end 44.749466 -252.141736)
		(width 0.101854)
		(layer "F.Cu")
		(net "M_B_CPU1_SB_CA<1>")
	)
	(segment
		(start 51.064414 -251.716794)
		(end 49.959514 -251.716794)
		(width 0.20066)
		(layer "F.Cu")
		(net "M_B_CPU1_SB_CA<1>")
	)
	(segment
		(start 92.374212 -248.527824)
		(end 92.374212 -247.992138)
		(width 0.20066)
		(layer "F.Cu")
		(net "M_B_CPU1_SB_CA<1>")
	)
	(segment
		(start 47.882302 -251.712476)
		(end 47.753778 -251.841)
		(width 0.20066)
		(layer "F.Cu")
		(net "M_B_CPU1_SB_CA<1>")
	)
	(segment
		(start 63.330582 -251.667772)
		(end 62.918086 -251.667772)
		(width 0.18288)
		(layer "In2.Cu")
		(net "M_B_CPU1_SB_CA<1>")
	)
	(segment
		(start 63.78067 -252.11786)
		(end 63.330582 -251.667772)
		(width 0.18288)
		(layer "In2.Cu")
		(net "M_B_CPU1_SB_CA<1>")
	)
	(segment
		(start 67.457066 -251.515118)
		(end 67.116198 -251.515118)
		(width 0.18288)
		(layer "In2.Cu")
		(net "M_B_CPU1_SB_CA<1>")
	)
	(segment
		(start 68.375784 -252.34392)
		(end 68.182744 -252.53696)
		(width 0.18288)
		(layer "In2.Cu")
		(net "M_B_CPU1_SB_CA<1>")
	)
	(segment
		(start 87.407496 -249.12193)
		(end 87.392764 -249.130566)
		(width 0.088646)
		(layer "In2.Cu")
		(net "M_B_CPU1_SB_CA<1>")
	)
	(segment
		(start 85.56244 -249.05462)
		(end 84.850224 -249.766836)
		(width 0.088646)
		(layer "In2.Cu")
		(net "M_B_CPU1_SB_CA<1>")
	)
	(segment
		(start 62.918086 -251.667772)
		(end 62.438788 -252.14707)
		(width 0.18288)
		(layer "In2.Cu")
		(net "M_B_CPU1_SB_CA<1>")
	)
	(segment
		(start 56.29656 -251.826776)
		(end 55.340758 -251.826776)
		(width 0.18288)
		(layer "In2.Cu")
		(net "M_B_CPU1_SB_CA<1>")
	)
	(segment
		(start 76.496926 -248.637806)
		(end 72.617838 -252.516894)
		(width 0.18288)
		(layer "In2.Cu")
		(net "M_B_CPU1_SB_CA<1>")
	)
	(segment
		(start 55.340758 -251.826776)
		(end 55.023512 -252.144022)
		(width 0.18288)
		(layer "In2.Cu")
		(net "M_B_CPU1_SB_CA<1>")
	)
	(segment
		(start 88.347296 -249.12193)
		(end 88.332564 -249.130566)
		(width 0.088646)
		(layer "In2.Cu")
		(net "M_B_CPU1_SB_CA<1>")
	)
	(segment
		(start 67.843146 -252.53696)
		(end 67.650106 -252.34392)
		(width 0.18288)
		(layer "In2.Cu")
		(net "M_B_CPU1_SB_CA<1>")
	)
	(segment
		(start 69.165216 -252.323854)
		(end 69.165216 -251.708158)
		(width 0.18288)
		(layer "In2.Cu")
		(net "M_B_CPU1_SB_CA<1>")
	)
	(segment
		(start 89.287096 -249.12193)
		(end 89.272364 -249.130566)
		(width 0.088646)
		(layer "In2.Cu")
		(net "M_B_CPU1_SB_CA<1>")
	)
	(segment
		(start 90.221054 -249.125486)
		(end 90.212164 -249.130566)
		(width 0.088646)
		(layer "In2.Cu")
		(net "M_B_CPU1_SB_CA<1>")
	)
	(segment
		(start 91.651074 -248.299478)
		(end 91.621864 -248.316496)
		(width 0.088646)
		(layer "In2.Cu")
		(net "M_B_CPU1_SB_CA<1>")
	)
	(segment
		(start 80.77327 -249.766836)
		(end 79.64424 -248.637806)
		(width 0.18288)
		(layer "In2.Cu")
		(net "M_B_CPU1_SB_CA<1>")
	)
	(segment
		(start 67.650106 -252.34392)
		(end 67.650106 -251.708158)
		(width 0.18288)
		(layer "In2.Cu")
		(net "M_B_CPU1_SB_CA<1>")
	)
	(segment
		(start 68.568824 -251.515118)
		(end 68.375784 -251.708158)
		(width 0.18288)
		(layer "In2.Cu")
		(net "M_B_CPU1_SB_CA<1>")
	)
	(segment
		(start 67.116198 -251.515118)
		(end 66.923158 -251.708158)
		(width 0.18288)
		(layer "In2.Cu")
		(net "M_B_CPU1_SB_CA<1>")
	)
	(segment
		(start 85.795612 -249.05462)
		(end 85.56244 -249.05462)
		(width 0.088646)
		(layer "In2.Cu")
		(net "M_B_CPU1_SB_CA<1>")
	)
	(segment
		(start 84.434934 -249.766836)
		(end 80.77327 -249.766836)
		(width 0.18288)
		(layer "In2.Cu")
		(net "M_B_CPU1_SB_CA<1>")
	)
	(segment
		(start 90.399362 -248.791984)
		(end 90.399616 -248.806208)
		(width 0.088646)
		(layer "In2.Cu")
		(net "M_B_CPU1_SB_CA<1>")
	)
	(segment
		(start 69.358256 -252.516894)
		(end 69.165216 -252.323854)
		(width 0.18288)
		(layer "In2.Cu")
		(net "M_B_CPU1_SB_CA<1>")
	)
	(segment
		(start 68.972176 -251.515118)
		(end 68.568824 -251.515118)
		(width 0.18288)
		(layer "In2.Cu")
		(net "M_B_CPU1_SB_CA<1>")
	)
	(segment
		(start 68.375784 -251.708158)
		(end 68.375784 -252.34392)
		(width 0.18288)
		(layer "In2.Cu")
		(net "M_B_CPU1_SB_CA<1>")
	)
	(segment
		(start 79.64424 -248.637806)
		(end 76.496926 -248.637806)
		(width 0.18288)
		(layer "In2.Cu")
		(net "M_B_CPU1_SB_CA<1>")
	)
	(segment
		(start 69.165216 -251.708158)
		(end 68.972176 -251.515118)
		(width 0.18288)
		(layer "In2.Cu")
		(net "M_B_CPU1_SB_CA<1>")
	)
	(segment
		(start 68.182744 -252.53696)
		(end 67.843146 -252.53696)
		(width 0.18288)
		(layer "In2.Cu")
		(net "M_B_CPU1_SB_CA<1>")
	)
	(segment
		(start 66.730118 -252.11786)
		(end 63.78067 -252.11786)
		(width 0.18288)
		(layer "In2.Cu")
		(net "M_B_CPU1_SB_CA<1>")
	)
	(segment
		(start 86.467696 -249.12193)
		(end 86.452964 -249.130566)
		(width 0.088646)
		(layer "In2.Cu")
		(net "M_B_CPU1_SB_CA<1>")
	)
	(segment
		(start 72.617838 -252.516894)
		(end 69.358256 -252.516894)
		(width 0.18288)
		(layer "In2.Cu")
		(net "M_B_CPU1_SB_CA<1>")
	)
	(segment
		(start 55.023512 -252.144022)
		(end 51.491642 -252.144022)
		(width 0.18288)
		(layer "In2.Cu")
		(net "M_B_CPU1_SB_CA<1>")
	)
	(segment
		(start 51.491642 -252.144022)
		(end 51.064414 -251.716794)
		(width 0.18288)
		(layer "In2.Cu")
		(net "M_B_CPU1_SB_CA<1>")
	)
	(segment
		(start 84.850224 -249.766836)
		(end 84.434934 -249.766836)
		(width 0.088646)
		(layer "In2.Cu")
		(net "M_B_CPU1_SB_CA<1>")
	)
	(segment
		(start 62.438788 -252.14707)
		(end 56.616854 -252.14707)
		(width 0.18288)
		(layer "In2.Cu")
		(net "M_B_CPU1_SB_CA<1>")
	)
	(segment
		(start 67.650106 -251.708158)
		(end 67.457066 -251.515118)
		(width 0.18288)
		(layer "In2.Cu")
		(net "M_B_CPU1_SB_CA<1>")
	)
	(segment
		(start 92.374212 -247.992138)
		(end 91.651074 -248.299478)
		(width 0.088646)
		(layer "In2.Cu")
		(net "M_B_CPU1_SB_CA<1>")
	)
	(segment
		(start 66.923158 -251.92482)
		(end 66.730118 -252.11786)
		(width 0.18288)
		(layer "In2.Cu")
		(net "M_B_CPU1_SB_CA<1>")
	)
	(segment
		(start 56.616854 -252.14707)
		(end 56.29656 -251.826776)
		(width 0.18288)
		(layer "In2.Cu")
		(net "M_B_CPU1_SB_CA<1>")
	)
	(segment
		(start 66.923158 -251.708158)
		(end 66.923158 -251.92482)
		(width 0.18288)
		(layer "In2.Cu")
		(net "M_B_CPU1_SB_CA<1>")
	)
	(arc
		(start 89.272364 -249.130566)
		(mid 89.085166 -249.180709)
		(end 88.897968 -249.130566)
		(width 0.088646)
		(layer "In2.Cu")
		(net "M_B_CPU1_SB_CA<1>")
	)
	(arc
		(start 89.837768 -249.130566)
		(mid 89.563569 -249.054731)
		(end 89.287096 -249.12193)
		(width 0.088646)
		(layer "In2.Cu")
		(net "M_B_CPU1_SB_CA<1>")
	)
	(arc
		(start 86.452964 -249.130566)
		(mid 86.265766 -249.180709)
		(end 86.078568 -249.130566)
		(width 0.088646)
		(layer "In2.Cu")
		(net "M_B_CPU1_SB_CA<1>")
	)
	(arc
		(start 87.392764 -249.130566)
		(mid 87.205566 -249.180709)
		(end 87.018368 -249.130566)
		(width 0.088646)
		(layer "In2.Cu")
		(net "M_B_CPU1_SB_CA<1>")
	)
	(arc
		(start 87.958168 -249.130566)
		(mid 87.683969 -249.054731)
		(end 87.407496 -249.12193)
		(width 0.088646)
		(layer "In2.Cu")
		(net "M_B_CPU1_SB_CA<1>")
	)
	(arc
		(start 90.212164 -249.130566)
		(mid 90.024966 -249.180709)
		(end 89.837768 -249.130566)
		(width 0.088646)
		(layer "In2.Cu")
		(net "M_B_CPU1_SB_CA<1>")
	)
	(arc
		(start 90.399616 -248.806208)
		(mid 90.351937 -248.989108)
		(end 90.221054 -249.125486)
		(width 0.088646)
		(layer "In2.Cu")
		(net "M_B_CPU1_SB_CA<1>")
	)
	(arc
		(start 87.018368 -249.130566)
		(mid 86.744169 -249.054731)
		(end 86.467696 -249.12193)
		(width 0.088646)
		(layer "In2.Cu")
		(net "M_B_CPU1_SB_CA<1>")
	)
	(arc
		(start 88.897968 -249.130566)
		(mid 88.623769 -249.054731)
		(end 88.347296 -249.12193)
		(width 0.088646)
		(layer "In2.Cu")
		(net "M_B_CPU1_SB_CA<1>")
	)
	(arc
		(start 91.621864 -248.316496)
		(mid 91.434666 -248.366639)
		(end 91.247468 -248.316496)
		(width 0.088646)
		(layer "In2.Cu")
		(net "M_B_CPU1_SB_CA<1>")
	)
	(arc
		(start 86.078568 -249.130566)
		(mid 85.942096 -249.073943)
		(end 85.795612 -249.05462)
		(width 0.088646)
		(layer "In2.Cu")
		(net "M_B_CPU1_SB_CA<1>")
	)
	(arc
		(start 91.247468 -248.316496)
		(mid 90.688207 -248.313001)
		(end 90.399362 -248.791984)
		(width 0.088646)
		(layer "In2.Cu")
		(net "M_B_CPU1_SB_CA<1>")
	)
	(arc
		(start 88.332564 -249.130566)
		(mid 88.145366 -249.180709)
		(end 87.958168 -249.130566)
		(width 0.088646)
		(layer "In2.Cu")
		(net "M_B_CPU1_SB_CA<1>")
	)
	(segment
		(start 41.3004 -252.141736)
		(end 41.29151 -252.132846)
		(width 0.1016)
		(layer "F.Cu")
		(net "M_B_CPU1_SB_CA<0>")
	)
	(segment
		(start 39.861236 -252.778006)
		(end 39.649908 -252.566678)
		(width 0.20066)
		(layer "F.Cu")
		(net "M_B_CPU1_SB_CA<0>")
	)
	(segment
		(start 41.29151 -252.132846)
		(end 40.682672 -252.132846)
		(width 0.20066)
		(layer "F.Cu")
		(net "M_B_CPU1_SB_CA<0>")
	)
	(segment
		(start 40.520112 -252.295406)
		(end 40.520112 -252.623574)
		(width 0.20066)
		(layer "F.Cu")
		(net "M_B_CPU1_SB_CA<0>")
	)
	(segment
		(start 43.795188 -252.141736)
		(end 43.616626 -252.141736)
		(width 0.20066)
		(layer "F.Cu")
		(net "M_B_CPU1_SB_CA<0>")
	)
	(segment
		(start 40.36568 -252.778006)
		(end 39.861236 -252.778006)
		(width 0.20066)
		(layer "F.Cu")
		(net "M_B_CPU1_SB_CA<0>")
	)
	(segment
		(start 39.649908 -252.566678)
		(end 38.315646 -252.566678)
		(width 0.20066)
		(layer "F.Cu")
		(net "M_B_CPU1_SB_CA<0>")
	)
	(segment
		(start 40.520112 -252.623574)
		(end 40.36568 -252.778006)
		(width 0.20066)
		(layer "F.Cu")
		(net "M_B_CPU1_SB_CA<0>")
	)
	(segment
		(start 43.285918 -252.141736)
		(end 41.3004 -252.141736)
		(width 0.1016)
		(layer "F.Cu")
		(net "M_B_CPU1_SB_CA<0>")
	)
	(segment
		(start 45.859446 -252.566678)
		(end 44.22013 -252.566678)
		(width 0.20066)
		(layer "F.Cu")
		(net "M_B_CPU1_SB_CA<0>")
	)
	(segment
		(start 44.22013 -252.566678)
		(end 43.795188 -252.141736)
		(width 0.20066)
		(layer "F.Cu")
		(net "M_B_CPU1_SB_CA<0>")
	)
	(segment
		(start 91.904312 -249.342148)
		(end 91.904566 -249.341894)
		(width 0.20066)
		(layer "F.Cu")
		(net "M_B_CPU1_SB_CA<0>")
	)
	(segment
		(start 40.682672 -252.132846)
		(end 40.520112 -252.295406)
		(width 0.20066)
		(layer "F.Cu")
		(net "M_B_CPU1_SB_CA<0>")
	)
	(segment
		(start 43.616626 -252.141736)
		(end 43.285918 -252.141736)
		(width 0.101854)
		(layer "F.Cu")
		(net "M_B_CPU1_SB_CA<0>")
	)
	(segment
		(start 46.964346 -252.566678)
		(end 45.859446 -252.566678)
		(width 0.20066)
		(layer "F.Cu")
		(net "M_B_CPU1_SB_CA<0>")
	)
	(segment
		(start 91.904566 -249.341894)
		(end 91.904566 -248.806208)
		(width 0.20066)
		(layer "F.Cu")
		(net "M_B_CPU1_SB_CA<0>")
	)
	(segment
		(start 84.774024 -250.112276)
		(end 84.434934 -250.112276)
		(width 0.088646)
		(layer "In2.Cu")
		(net "M_B_CPU1_SB_CA<0>")
	)
	(segment
		(start 76.871322 -248.983246)
		(end 72.795384 -253.059184)
		(width 0.18288)
		(layer "In2.Cu")
		(net "M_B_CPU1_SB_CA<0>")
	)
	(segment
		(start 90.590116 -248.806208)
		(end 90.590116 -248.816114)
		(width 0.088646)
		(layer "In2.Cu")
		(net "M_B_CPU1_SB_CA<0>")
	)
	(segment
		(start 49.014888 -253.059184)
		(end 48.522382 -252.566678)
		(width 0.18288)
		(layer "In2.Cu")
		(net "M_B_CPU1_SB_CA<0>")
	)
	(segment
		(start 90.777314 -248.48185)
		(end 90.768424 -248.48693)
		(width 0.088646)
		(layer "In2.Cu")
		(net "M_B_CPU1_SB_CA<0>")
	)
	(segment
		(start 87.488014 -249.295666)
		(end 87.473282 -249.304302)
		(width 0.088646)
		(layer "In2.Cu")
		(net "M_B_CPU1_SB_CA<0>")
	)
	(segment
		(start 80.419448 -250.112276)
		(end 79.290418 -248.983246)
		(width 0.18288)
		(layer "In2.Cu")
		(net "M_B_CPU1_SB_CA<0>")
	)
	(segment
		(start 90.589862 -248.806208)
		(end 90.590116 -248.806208)
		(width 0.088646)
		(layer "In2.Cu")
		(net "M_B_CPU1_SB_CA<0>")
	)
	(segment
		(start 86.548214 -249.295666)
		(end 86.533482 -249.304302)
		(width 0.088646)
		(layer "In2.Cu")
		(net "M_B_CPU1_SB_CA<0>")
	)
	(segment
		(start 90.307668 -249.295666)
		(end 90.297254 -249.301762)
		(width 0.088646)
		(layer "In2.Cu")
		(net "M_B_CPU1_SB_CA<0>")
	)
	(segment
		(start 79.290418 -248.983246)
		(end 76.871322 -248.983246)
		(width 0.18288)
		(layer "In2.Cu")
		(net "M_B_CPU1_SB_CA<0>")
	)
	(segment
		(start 88.427814 -249.295666)
		(end 88.413082 -249.304302)
		(width 0.088646)
		(layer "In2.Cu")
		(net "M_B_CPU1_SB_CA<0>")
	)
	(segment
		(start 91.904566 -248.806208)
		(end 91.541092 -248.705116)
		(width 0.088646)
		(layer "In2.Cu")
		(net "M_B_CPU1_SB_CA<0>")
	)
	(segment
		(start 89.367614 -249.295666)
		(end 89.352882 -249.304302)
		(width 0.088646)
		(layer "In2.Cu")
		(net "M_B_CPU1_SB_CA<0>")
	)
	(segment
		(start 72.795384 -253.059184)
		(end 49.014888 -253.059184)
		(width 0.18288)
		(layer "In2.Cu")
		(net "M_B_CPU1_SB_CA<0>")
	)
	(segment
		(start 84.434934 -250.112276)
		(end 80.419448 -250.112276)
		(width 0.18288)
		(layer "In2.Cu")
		(net "M_B_CPU1_SB_CA<0>")
	)
	(segment
		(start 48.522382 -252.566678)
		(end 46.964346 -252.566678)
		(width 0.18288)
		(layer "In2.Cu")
		(net "M_B_CPU1_SB_CA<0>")
	)
	(segment
		(start 85.641434 -249.244866)
		(end 84.774024 -250.112276)
		(width 0.088646)
		(layer "In2.Cu")
		(net "M_B_CPU1_SB_CA<0>")
	)
	(segment
		(start 85.795612 -249.244866)
		(end 85.641434 -249.244866)
		(width 0.088646)
		(layer "In2.Cu")
		(net "M_B_CPU1_SB_CA<0>")
	)
	(arc
		(start 90.794586 -248.472706)
		(mid 90.785874 -248.477134)
		(end 90.777314 -248.48185)
		(width 0.088646)
		(layer "In2.Cu")
		(net "M_B_CPU1_SB_CA<0>")
	)
	(arc
		(start 91.102942 -248.458228)
		(mid 90.947203 -248.43221)
		(end 90.794586 -248.472706)
		(width 0.088646)
		(layer "In2.Cu")
		(net "M_B_CPU1_SB_CA<0>")
	)
	(arc
		(start 90.768424 -248.48693)
		(mid 90.63751 -248.62329)
		(end 90.589862 -248.806208)
		(width 0.088646)
		(layer "In2.Cu")
		(net "M_B_CPU1_SB_CA<0>")
	)
	(arc
		(start 88.80221 -249.295666)
		(mid 88.615012 -249.245523)
		(end 88.427814 -249.295666)
		(width 0.088646)
		(layer "In2.Cu")
		(net "M_B_CPU1_SB_CA<0>")
	)
	(arc
		(start 90.590116 -248.816114)
		(mid 90.512005 -249.093063)
		(end 90.307668 -249.295666)
		(width 0.088646)
		(layer "In2.Cu")
		(net "M_B_CPU1_SB_CA<0>")
	)
	(arc
		(start 88.413082 -249.304302)
		(mid 88.136607 -249.371622)
		(end 87.86241 -249.295666)
		(width 0.088646)
		(layer "In2.Cu")
		(net "M_B_CPU1_SB_CA<0>")
	)
	(arc
		(start 89.74201 -249.295666)
		(mid 89.554812 -249.245523)
		(end 89.367614 -249.295666)
		(width 0.088646)
		(layer "In2.Cu")
		(net "M_B_CPU1_SB_CA<0>")
	)
	(arc
		(start 91.541092 -248.705116)
		(mid 91.42939 -248.626623)
		(end 91.312238 -248.556526)
		(width 0.088646)
		(layer "In2.Cu")
		(net "M_B_CPU1_SB_CA<0>")
	)
	(arc
		(start 87.86241 -249.295666)
		(mid 87.675212 -249.245523)
		(end 87.488014 -249.295666)
		(width 0.088646)
		(layer "In2.Cu")
		(net "M_B_CPU1_SB_CA<0>")
	)
	(arc
		(start 89.352882 -249.304302)
		(mid 89.076407 -249.371622)
		(end 88.80221 -249.295666)
		(width 0.088646)
		(layer "In2.Cu")
		(net "M_B_CPU1_SB_CA<0>")
	)
	(arc
		(start 85.98281 -249.295666)
		(mid 85.892554 -249.257944)
		(end 85.795612 -249.244866)
		(width 0.088646)
		(layer "In2.Cu")
		(net "M_B_CPU1_SB_CA<0>")
	)
	(arc
		(start 86.92261 -249.295666)
		(mid 86.735412 -249.245523)
		(end 86.548214 -249.295666)
		(width 0.088646)
		(layer "In2.Cu")
		(net "M_B_CPU1_SB_CA<0>")
	)
	(arc
		(start 91.312238 -248.556526)
		(mid 91.272347 -248.536625)
		(end 91.231212 -248.519442)
		(width 0.088646)
		(layer "In2.Cu")
		(net "M_B_CPU1_SB_CA<0>")
	)
	(arc
		(start 86.533482 -249.304302)
		(mid 86.257007 -249.371622)
		(end 85.98281 -249.295666)
		(width 0.088646)
		(layer "In2.Cu")
		(net "M_B_CPU1_SB_CA<0>")
	)
	(arc
		(start 91.126056 -248.467626)
		(mid 91.114515 -248.462888)
		(end 91.102942 -248.458228)
		(width 0.088646)
		(layer "In2.Cu")
		(net "M_B_CPU1_SB_CA<0>")
	)
	(arc
		(start 91.152218 -248.481342)
		(mid 91.139273 -248.474224)
		(end 91.126056 -248.467626)
		(width 0.088646)
		(layer "In2.Cu")
		(net "M_B_CPU1_SB_CA<0>")
	)
	(arc
		(start 87.473282 -249.304302)
		(mid 87.196807 -249.371622)
		(end 86.92261 -249.295666)
		(width 0.088646)
		(layer "In2.Cu")
		(net "M_B_CPU1_SB_CA<0>")
	)
	(arc
		(start 91.231212 -248.519442)
		(mid 91.190977 -248.501922)
		(end 91.152218 -248.481342)
		(width 0.088646)
		(layer "In2.Cu")
		(net "M_B_CPU1_SB_CA<0>")
	)
	(arc
		(start 90.297254 -249.301762)
		(mid 90.018822 -249.371608)
		(end 89.74201 -249.295666)
		(width 0.088646)
		(layer "In2.Cu")
		(net "M_B_CPU1_SB_CA<0>")
	)
	(segment
		(start 98.592894 -253.383796)
		(end 98.592894 -253.919482)
		(width 0.20066)
		(layer "F.Cu")
		(net "M_B_CPU1_SA_RSP<1>")
	)
	(segment
		(start 98.592894 -253.919482)
		(end 98.593148 -253.919736)
		(width 0.20066)
		(layer "F.Cu")
		(net "M_B_CPU1_SA_RSP<1>")
	)
	(segment
		(start 45.859446 -244.066568)
		(end 46.964346 -244.066568)
		(width 0.20066)
		(layer "F.Cu")
		(net "M_B_CPU1_SA_RSP<1>")
	)
	(segment
		(start 52.84089 -247.22836)
		(end 52.84089 -246.442992)
		(width 0.18288)
		(layer "In6.Cu")
		(net "M_B_CPU1_SA_RSP<1>")
	)
	(segment
		(start 98.592894 -252.086618)
		(end 97.96272 -251.456444)
		(width 0.18288)
		(layer "In6.Cu")
		(net "M_B_CPU1_SA_RSP<1>")
	)
	(segment
		(start 54.666896 -247.0658)
		(end 54.341776 -247.0658)
		(width 0.18288)
		(layer "In6.Cu")
		(net "M_B_CPU1_SA_RSP<1>")
	)
	(segment
		(start 59.262264 -248.266966)
		(end 58.911236 -247.915938)
		(width 0.18288)
		(layer "In6.Cu")
		(net "M_B_CPU1_SA_RSP<1>")
	)
	(segment
		(start 72.95769 -251.355606)
		(end 68.855082 -251.355606)
		(width 0.18288)
		(layer "In6.Cu")
		(net "M_B_CPU1_SA_RSP<1>")
	)
	(segment
		(start 50.122328 -246.191024)
		(end 49.23917 -245.307866)
		(width 0.18288)
		(layer "In6.Cu")
		(net "M_B_CPU1_SA_RSP<1>")
	)
	(segment
		(start 51.345338 -246.191024)
		(end 50.122328 -246.191024)
		(width 0.18288)
		(layer "In6.Cu")
		(net "M_B_CPU1_SA_RSP<1>")
	)
	(segment
		(start 60.310776 -249.467624)
		(end 59.619896 -249.467624)
		(width 0.18288)
		(layer "In6.Cu")
		(net "M_B_CPU1_SA_RSP<1>")
	)
	(segment
		(start 60.493656 -249.650504)
		(end 60.310776 -249.467624)
		(width 0.18288)
		(layer "In6.Cu")
		(net "M_B_CPU1_SA_RSP<1>")
	)
	(segment
		(start 98.592894 -253.032006)
		(end 98.592894 -252.781308)
		(width 0.088646)
		(layer "In6.Cu")
		(net "M_B_CPU1_SA_RSP<1>")
	)
	(segment
		(start 61.001656 -250.119896)
		(end 60.676536 -250.119896)
		(width 0.18288)
		(layer "In6.Cu")
		(net "M_B_CPU1_SA_RSP<1>")
	)
	(segment
		(start 61.184536 -249.650504)
		(end 61.184536 -249.937016)
		(width 0.18288)
		(layer "In6.Cu")
		(net "M_B_CPU1_SA_RSP<1>")
	)
	(segment
		(start 55.493412 -247.672606)
		(end 55.032656 -247.672606)
		(width 0.18288)
		(layer "In6.Cu")
		(net "M_B_CPU1_SA_RSP<1>")
	)
	(segment
		(start 67.571366 -250.823984)
		(end 66.68516 -249.937778)
		(width 0.18288)
		(layer "In6.Cu")
		(net "M_B_CPU1_SA_RSP<1>")
	)
	(segment
		(start 54.158896 -247.24868)
		(end 54.158896 -247.489726)
		(width 0.18288)
		(layer "In6.Cu")
		(net "M_B_CPU1_SA_RSP<1>")
	)
	(segment
		(start 55.736744 -247.915938)
		(end 55.493412 -247.672606)
		(width 0.18288)
		(layer "In6.Cu")
		(net "M_B_CPU1_SA_RSP<1>")
	)
	(segment
		(start 61.367416 -249.467624)
		(end 61.184536 -249.650504)
		(width 0.18288)
		(layer "In6.Cu")
		(net "M_B_CPU1_SA_RSP<1>")
	)
	(segment
		(start 54.849776 -247.24868)
		(end 54.666896 -247.0658)
		(width 0.18288)
		(layer "In6.Cu")
		(net "M_B_CPU1_SA_RSP<1>")
	)
	(segment
		(start 56.99887 -248.098818)
		(end 56.81599 -247.915938)
		(width 0.18288)
		(layer "In6.Cu")
		(net "M_B_CPU1_SA_RSP<1>")
	)
	(segment
		(start 52.84089 -246.442992)
		(end 52.518564 -246.120666)
		(width 0.18288)
		(layer "In6.Cu")
		(net "M_B_CPU1_SA_RSP<1>")
	)
	(segment
		(start 57.68975 -248.92381)
		(end 57.50687 -249.10669)
		(width 0.18288)
		(layer "In6.Cu")
		(net "M_B_CPU1_SA_RSP<1>")
	)
	(segment
		(start 68.855082 -251.355606)
		(end 67.571366 -250.823984)
		(width 0.18288)
		(layer "In6.Cu")
		(net "M_B_CPU1_SA_RSP<1>")
	)
	(segment
		(start 64.40424 -248.992898)
		(end 64.065912 -248.65457)
		(width 0.18288)
		(layer "In6.Cu")
		(net "M_B_CPU1_SA_RSP<1>")
	)
	(segment
		(start 51.415696 -246.120666)
		(end 51.345338 -246.191024)
		(width 0.18288)
		(layer "In6.Cu")
		(net "M_B_CPU1_SA_RSP<1>")
	)
	(segment
		(start 64.065912 -248.65457)
		(end 63.271654 -248.65457)
		(width 0.18288)
		(layer "In6.Cu")
		(net "M_B_CPU1_SA_RSP<1>")
	)
	(segment
		(start 53.976016 -247.672606)
		(end 53.285136 -247.672606)
		(width 0.18288)
		(layer "In6.Cu")
		(net "M_B_CPU1_SA_RSP<1>")
	)
	(segment
		(start 60.676536 -250.119896)
		(end 60.493656 -249.937016)
		(width 0.18288)
		(layer "In6.Cu")
		(net "M_B_CPU1_SA_RSP<1>")
	)
	(segment
		(start 56.99887 -248.92381)
		(end 56.99887 -248.098818)
		(width 0.18288)
		(layer "In6.Cu")
		(net "M_B_CPU1_SA_RSP<1>")
	)
	(segment
		(start 54.849776 -247.489726)
		(end 54.849776 -247.24868)
		(width 0.18288)
		(layer "In6.Cu")
		(net "M_B_CPU1_SA_RSP<1>")
	)
	(segment
		(start 81.899252 -251.262134)
		(end 79.293212 -248.656094)
		(width 0.18288)
		(layer "In6.Cu")
		(net "M_B_CPU1_SA_RSP<1>")
	)
	(segment
		(start 98.592894 -252.781308)
		(end 98.592894 -252.086618)
		(width 0.18288)
		(layer "In6.Cu")
		(net "M_B_CPU1_SA_RSP<1>")
	)
	(segment
		(start 62.4586 -249.467624)
		(end 61.367416 -249.467624)
		(width 0.18288)
		(layer "In6.Cu")
		(net "M_B_CPU1_SA_RSP<1>")
	)
	(segment
		(start 57.50687 -249.10669)
		(end 57.18175 -249.10669)
		(width 0.18288)
		(layer "In6.Cu")
		(net "M_B_CPU1_SA_RSP<1>")
	)
	(segment
		(start 87.806784 -251.262134)
		(end 81.899252 -251.262134)
		(width 0.18288)
		(layer "In6.Cu")
		(net "M_B_CPU1_SA_RSP<1>")
	)
	(segment
		(start 57.87263 -247.915938)
		(end 57.68975 -248.098818)
		(width 0.18288)
		(layer "In6.Cu")
		(net "M_B_CPU1_SA_RSP<1>")
	)
	(segment
		(start 61.184536 -249.937016)
		(end 61.001656 -250.119896)
		(width 0.18288)
		(layer "In6.Cu")
		(net "M_B_CPU1_SA_RSP<1>")
	)
	(segment
		(start 59.262264 -249.109992)
		(end 59.262264 -248.266966)
		(width 0.18288)
		(layer "In6.Cu")
		(net "M_B_CPU1_SA_RSP<1>")
	)
	(segment
		(start 54.158896 -247.489726)
		(end 53.976016 -247.672606)
		(width 0.18288)
		(layer "In6.Cu")
		(net "M_B_CPU1_SA_RSP<1>")
	)
	(segment
		(start 79.293212 -248.656094)
		(end 75.657202 -248.656094)
		(width 0.18288)
		(layer "In6.Cu")
		(net "M_B_CPU1_SA_RSP<1>")
	)
	(segment
		(start 59.619896 -249.467624)
		(end 59.262264 -249.109992)
		(width 0.18288)
		(layer "In6.Cu")
		(net "M_B_CPU1_SA_RSP<1>")
	)
	(segment
		(start 97.96272 -251.456444)
		(end 88.001094 -251.456444)
		(width 0.18288)
		(layer "In6.Cu")
		(net "M_B_CPU1_SA_RSP<1>")
	)
	(segment
		(start 56.81599 -247.915938)
		(end 55.736744 -247.915938)
		(width 0.18288)
		(layer "In6.Cu")
		(net "M_B_CPU1_SA_RSP<1>")
	)
	(segment
		(start 57.18175 -249.10669)
		(end 56.99887 -248.92381)
		(width 0.18288)
		(layer "In6.Cu")
		(net "M_B_CPU1_SA_RSP<1>")
	)
	(segment
		(start 58.911236 -247.915938)
		(end 57.87263 -247.915938)
		(width 0.18288)
		(layer "In6.Cu")
		(net "M_B_CPU1_SA_RSP<1>")
	)
	(segment
		(start 55.032656 -247.672606)
		(end 54.849776 -247.489726)
		(width 0.18288)
		(layer "In6.Cu")
		(net "M_B_CPU1_SA_RSP<1>")
	)
	(segment
		(start 57.68975 -248.098818)
		(end 57.68975 -248.92381)
		(width 0.18288)
		(layer "In6.Cu")
		(net "M_B_CPU1_SA_RSP<1>")
	)
	(segment
		(start 54.341776 -247.0658)
		(end 54.158896 -247.24868)
		(width 0.18288)
		(layer "In6.Cu")
		(net "M_B_CPU1_SA_RSP<1>")
	)
	(segment
		(start 98.593148 -253.919736)
		(end 98.592894 -253.032006)
		(width 0.088646)
		(layer "In6.Cu")
		(net "M_B_CPU1_SA_RSP<1>")
	)
	(segment
		(start 66.68516 -249.937778)
		(end 64.40424 -248.992898)
		(width 0.18288)
		(layer "In6.Cu")
		(net "M_B_CPU1_SA_RSP<1>")
	)
	(segment
		(start 49.23917 -245.307866)
		(end 48.205644 -245.307866)
		(width 0.18288)
		(layer "In6.Cu")
		(net "M_B_CPU1_SA_RSP<1>")
	)
	(segment
		(start 63.271654 -248.65457)
		(end 62.4586 -249.467624)
		(width 0.18288)
		(layer "In6.Cu")
		(net "M_B_CPU1_SA_RSP<1>")
	)
	(segment
		(start 48.205644 -245.307866)
		(end 46.964346 -244.066568)
		(width 0.18288)
		(layer "In6.Cu")
		(net "M_B_CPU1_SA_RSP<1>")
	)
	(segment
		(start 75.657202 -248.656094)
		(end 72.95769 -251.355606)
		(width 0.18288)
		(layer "In6.Cu")
		(net "M_B_CPU1_SA_RSP<1>")
	)
	(segment
		(start 53.285136 -247.672606)
		(end 52.84089 -247.22836)
		(width 0.18288)
		(layer "In6.Cu")
		(net "M_B_CPU1_SA_RSP<1>")
	)
	(segment
		(start 52.518564 -246.120666)
		(end 51.415696 -246.120666)
		(width 0.18288)
		(layer "In6.Cu")
		(net "M_B_CPU1_SA_RSP<1>")
	)
	(segment
		(start 60.493656 -249.937016)
		(end 60.493656 -249.650504)
		(width 0.18288)
		(layer "In6.Cu")
		(net "M_B_CPU1_SA_RSP<1>")
	)
	(segment
		(start 88.001094 -251.456444)
		(end 87.806784 -251.262134)
		(width 0.18288)
		(layer "In6.Cu")
		(net "M_B_CPU1_SA_RSP<1>")
	)
	(segment
		(start 99.063048 -254.197612)
		(end 99.063048 -254.733298)
		(width 0.20066)
		(layer "F.Cu")
		(net "M_B_CPU1_SA_RSP<0>")
	)
	(segment
		(start 38.315646 -244.066568)
		(end 39.420546 -244.066568)
		(width 0.20066)
		(layer "F.Cu")
		(net "M_B_CPU1_SA_RSP<0>")
	)
	(segment
		(start 99.063048 -254.733298)
		(end 99.062794 -254.733552)
		(width 0.20066)
		(layer "F.Cu")
		(net "M_B_CPU1_SA_RSP<0>")
	)
	(segment
		(start 63.192152 -250.354084)
		(end 62.381384 -251.164852)
		(width 0.18288)
		(layer "In6.Cu")
		(net "M_B_CPU1_SA_RSP<0>")
	)
	(segment
		(start 68.639182 -252.441964)
		(end 65.703958 -251.22632)
		(width 0.18288)
		(layer "In6.Cu")
		(net "M_B_CPU1_SA_RSP<0>")
	)
	(segment
		(start 50.728626 -247.891046)
		(end 48.243998 -246.648478)
		(width 0.18288)
		(layer "In6.Cu")
		(net "M_B_CPU1_SA_RSP<0>")
	)
	(segment
		(start 99.062794 -254.733552)
		(end 98.366072 -254.438658)
		(width 0.088646)
		(layer "In6.Cu")
		(net "M_B_CPU1_SA_RSP<0>")
	)
	(segment
		(start 51.648106 -248.442226)
		(end 51.648106 -248.221246)
		(width 0.18288)
		(layer "In6.Cu")
		(net "M_B_CPU1_SA_RSP<0>")
	)
	(segment
		(start 52.494942 -248.945146)
		(end 51.998626 -248.792746)
		(width 0.18288)
		(layer "In6.Cu")
		(net "M_B_CPU1_SA_RSP<0>")
	)
	(segment
		(start 42.515028 -245.695978)
		(end 40.014398 -244.66042)
		(width 0.18288)
		(layer "In6.Cu")
		(net "M_B_CPU1_SA_RSP<0>")
	)
	(segment
		(start 97.388172 -252.49632)
		(end 88.023954 -252.49632)
		(width 0.18288)
		(layer "In6.Cu")
		(net "M_B_CPU1_SA_RSP<0>")
	)
	(segment
		(start 81.62036 -251.933202)
		(end 79.01432 -249.327162)
		(width 0.18288)
		(layer "In6.Cu")
		(net "M_B_CPU1_SA_RSP<0>")
	)
	(segment
		(start 51.317906 -247.891046)
		(end 50.728626 -247.891046)
		(width 0.18288)
		(layer "In6.Cu")
		(net "M_B_CPU1_SA_RSP<0>")
	)
	(segment
		(start 98.074734 -254.147066)
		(end 98.05289 -254.088646)
		(width 0.088646)
		(layer "In6.Cu")
		(net "M_B_CPU1_SA_RSP<0>")
	)
	(segment
		(start 51.998626 -248.792746)
		(end 51.648106 -248.442226)
		(width 0.18288)
		(layer "In6.Cu")
		(net "M_B_CPU1_SA_RSP<0>")
	)
	(segment
		(start 73.279508 -252.441964)
		(end 68.639182 -252.441964)
		(width 0.18288)
		(layer "In6.Cu")
		(net "M_B_CPU1_SA_RSP<0>")
	)
	(segment
		(start 98.027998 -253.564898)
		(end 97.52838 -253.06528)
		(width 0.088646)
		(layer "In6.Cu")
		(net "M_B_CPU1_SA_RSP<0>")
	)
	(segment
		(start 62.381384 -251.164852)
		(end 59.542172 -251.164852)
		(width 0.18288)
		(layer "In6.Cu")
		(net "M_B_CPU1_SA_RSP<0>")
	)
	(segment
		(start 48.243998 -246.648478)
		(end 47.37227 -246.191024)
		(width 0.18288)
		(layer "In6.Cu")
		(net "M_B_CPU1_SA_RSP<0>")
	)
	(segment
		(start 76.39431 -249.327162)
		(end 73.279508 -252.441964)
		(width 0.18288)
		(layer "In6.Cu")
		(net "M_B_CPU1_SA_RSP<0>")
	)
	(segment
		(start 43.010074 -246.191024)
		(end 42.515028 -245.695978)
		(width 0.18288)
		(layer "In6.Cu")
		(net "M_B_CPU1_SA_RSP<0>")
	)
	(segment
		(start 40.014398 -244.66042)
		(end 39.420546 -244.066568)
		(width 0.18288)
		(layer "In6.Cu")
		(net "M_B_CPU1_SA_RSP<0>")
	)
	(segment
		(start 98.176588 -254.303276)
		(end 98.136964 -254.255016)
		(width 0.088646)
		(layer "In6.Cu")
		(net "M_B_CPU1_SA_RSP<0>")
	)
	(segment
		(start 87.460836 -251.933202)
		(end 81.62036 -251.933202)
		(width 0.18288)
		(layer "In6.Cu")
		(net "M_B_CPU1_SA_RSP<0>")
	)
	(segment
		(start 55.362602 -250.182126)
		(end 54.675532 -249.495056)
		(width 0.18288)
		(layer "In6.Cu")
		(net "M_B_CPU1_SA_RSP<0>")
	)
	(segment
		(start 98.05289 -254.088646)
		(end 98.03765 -254.028448)
		(width 0.088646)
		(layer "In6.Cu")
		(net "M_B_CPU1_SA_RSP<0>")
	)
	(segment
		(start 98.366072 -254.438658)
		(end 98.330004 -254.420116)
		(width 0.088646)
		(layer "In6.Cu")
		(net "M_B_CPU1_SA_RSP<0>")
	)
	(segment
		(start 98.027998 -253.92761)
		(end 98.027998 -253.564898)
		(width 0.088646)
		(layer "In6.Cu")
		(net "M_B_CPU1_SA_RSP<0>")
	)
	(segment
		(start 97.52838 -253.06528)
		(end 97.52838 -252.781308)
		(width 0.088646)
		(layer "In6.Cu")
		(net "M_B_CPU1_SA_RSP<0>")
	)
	(segment
		(start 98.029014 -253.966472)
		(end 98.027998 -253.92761)
		(width 0.088646)
		(layer "In6.Cu")
		(net "M_B_CPU1_SA_RSP<0>")
	)
	(segment
		(start 65.063878 -250.58624)
		(end 64.503554 -250.354084)
		(width 0.18288)
		(layer "In6.Cu")
		(net "M_B_CPU1_SA_RSP<0>")
	)
	(segment
		(start 98.136964 -254.255016)
		(end 98.102928 -254.202692)
		(width 0.088646)
		(layer "In6.Cu")
		(net "M_B_CPU1_SA_RSP<0>")
	)
	(segment
		(start 65.703958 -251.22632)
		(end 65.063878 -250.58624)
		(width 0.18288)
		(layer "In6.Cu")
		(net "M_B_CPU1_SA_RSP<0>")
	)
	(segment
		(start 98.102928 -254.202692)
		(end 98.074734 -254.147066)
		(width 0.088646)
		(layer "In6.Cu")
		(net "M_B_CPU1_SA_RSP<0>")
	)
	(segment
		(start 97.52838 -252.636528)
		(end 97.388172 -252.49632)
		(width 0.18288)
		(layer "In6.Cu")
		(net "M_B_CPU1_SA_RSP<0>")
	)
	(segment
		(start 98.330004 -254.420116)
		(end 98.30435 -254.405638)
		(width 0.088646)
		(layer "In6.Cu")
		(net "M_B_CPU1_SA_RSP<0>")
	)
	(segment
		(start 98.221292 -254.34671)
		(end 98.176588 -254.303276)
		(width 0.088646)
		(layer "In6.Cu")
		(net "M_B_CPU1_SA_RSP<0>")
	)
	(segment
		(start 88.023954 -252.49632)
		(end 87.460836 -251.933202)
		(width 0.18288)
		(layer "In6.Cu")
		(net "M_B_CPU1_SA_RSP<0>")
	)
	(segment
		(start 51.648106 -248.221246)
		(end 51.317906 -247.891046)
		(width 0.18288)
		(layer "In6.Cu")
		(net "M_B_CPU1_SA_RSP<0>")
	)
	(segment
		(start 97.52838 -252.781308)
		(end 97.52838 -252.636528)
		(width 0.18288)
		(layer "In6.Cu")
		(net "M_B_CPU1_SA_RSP<0>")
	)
	(segment
		(start 79.01432 -249.327162)
		(end 76.39431 -249.327162)
		(width 0.18288)
		(layer "In6.Cu")
		(net "M_B_CPU1_SA_RSP<0>")
	)
	(segment
		(start 54.675532 -249.495056)
		(end 52.494942 -248.945146)
		(width 0.18288)
		(layer "In6.Cu")
		(net "M_B_CPU1_SA_RSP<0>")
	)
	(segment
		(start 59.542172 -251.164852)
		(end 58.559446 -250.182126)
		(width 0.18288)
		(layer "In6.Cu")
		(net "M_B_CPU1_SA_RSP<0>")
	)
	(segment
		(start 64.503554 -250.354084)
		(end 63.192152 -250.354084)
		(width 0.18288)
		(layer "In6.Cu")
		(net "M_B_CPU1_SA_RSP<0>")
	)
	(segment
		(start 98.30435 -254.405638)
		(end 98.270568 -254.38481)
		(width 0.088646)
		(layer "In6.Cu")
		(net "M_B_CPU1_SA_RSP<0>")
	)
	(segment
		(start 98.270568 -254.38481)
		(end 98.221292 -254.34671)
		(width 0.088646)
		(layer "In6.Cu")
		(net "M_B_CPU1_SA_RSP<0>")
	)
	(segment
		(start 98.03765 -254.028448)
		(end 98.029014 -253.966472)
		(width 0.088646)
		(layer "In6.Cu")
		(net "M_B_CPU1_SA_RSP<0>")
	)
	(segment
		(start 47.37227 -246.191024)
		(end 43.010074 -246.191024)
		(width 0.18288)
		(layer "In6.Cu")
		(net "M_B_CPU1_SA_RSP<0>")
	)
	(segment
		(start 58.559446 -250.182126)
		(end 55.362602 -250.182126)
		(width 0.18288)
		(layer "In6.Cu")
		(net "M_B_CPU1_SA_RSP<0>")
	)
	(segment
		(start 44.153074 -259.366766)
		(end 43.728132 -258.941824)
		(width 0.20066)
		(layer "F.Cu")
		(net "M_B_CPU1_SA_PAR")
	)
	(segment
		(start 43.616626 -258.941824)
		(end 43.285918 -258.941824)
		(width 0.101854)
		(layer "F.Cu")
		(net "M_B_CPU1_SA_PAR")
	)
	(segment
		(start 41.300146 -258.95554)
		(end 41.29151 -258.95554)
		(width 0.101854)
		(layer "F.Cu")
		(net "M_B_CPU1_SA_PAR")
	)
	(segment
		(start 46.964346 -259.366766)
		(end 45.859446 -259.366766)
		(width 0.20066)
		(layer "F.Cu")
		(net "M_B_CPU1_SA_PAR")
	)
	(segment
		(start 93.314266 -248.528078)
		(end 93.314012 -248.527824)
		(width 0.20066)
		(layer "F.Cu")
		(net "M_B_CPU1_SA_PAR")
	)
	(segment
		(start 45.859446 -259.366766)
		(end 44.153074 -259.366766)
		(width 0.20066)
		(layer "F.Cu")
		(net "M_B_CPU1_SA_PAR")
	)
	(segment
		(start 40.298878 -259.60578)
		(end 39.888922 -259.60578)
		(width 0.20066)
		(layer "F.Cu")
		(net "M_B_CPU1_SA_PAR")
	)
	(segment
		(start 40.660574 -258.95554)
		(end 40.66032 -258.955286)
		(width 0.20066)
		(layer "F.Cu")
		(net "M_B_CPU1_SA_PAR")
	)
	(segment
		(start 40.520112 -259.384546)
		(end 40.298878 -259.60578)
		(width 0.20066)
		(layer "F.Cu")
		(net "M_B_CPU1_SA_PAR")
	)
	(segment
		(start 40.66032 -258.955286)
		(end 40.520112 -259.095494)
		(width 0.20066)
		(layer "F.Cu")
		(net "M_B_CPU1_SA_PAR")
	)
	(segment
		(start 41.313862 -258.941824)
		(end 41.300146 -258.95554)
		(width 0.101854)
		(layer "F.Cu")
		(net "M_B_CPU1_SA_PAR")
	)
	(segment
		(start 39.888922 -259.60578)
		(end 39.649908 -259.366766)
		(width 0.20066)
		(layer "F.Cu")
		(net "M_B_CPU1_SA_PAR")
	)
	(segment
		(start 40.520112 -259.095494)
		(end 40.520112 -259.384546)
		(width 0.20066)
		(layer "F.Cu")
		(net "M_B_CPU1_SA_PAR")
	)
	(segment
		(start 43.285918 -258.941824)
		(end 41.313862 -258.941824)
		(width 0.1016)
		(layer "F.Cu")
		(net "M_B_CPU1_SA_PAR")
	)
	(segment
		(start 39.649908 -259.366766)
		(end 38.315646 -259.366766)
		(width 0.20066)
		(layer "F.Cu")
		(net "M_B_CPU1_SA_PAR")
	)
	(segment
		(start 41.29151 -258.95554)
		(end 40.660574 -258.95554)
		(width 0.20066)
		(layer "F.Cu")
		(net "M_B_CPU1_SA_PAR")
	)
	(segment
		(start 93.314012 -248.527824)
		(end 93.314012 -247.992138)
		(width 0.20066)
		(layer "F.Cu")
		(net "M_B_CPU1_SA_PAR")
	)
	(segment
		(start 43.728132 -258.941824)
		(end 43.616626 -258.941824)
		(width 0.20066)
		(layer "F.Cu")
		(net "M_B_CPU1_SA_PAR")
	)
	(segment
		(start 59.25566 -257.051048)
		(end 53.580284 -258.265168)
		(width 0.18288)
		(layer "In2.Cu")
		(net "M_B_CPU1_SA_PAR")
	)
	(segment
		(start 51.604926 -260.44906)
		(end 51.412394 -260.641592)
		(width 0.18288)
		(layer "In2.Cu")
		(net "M_B_CPU1_SA_PAR")
	)
	(segment
		(start 94.487746 -250.663202)
		(end 93.868748 -251.2822)
		(width 0.18288)
		(layer "In2.Cu")
		(net "M_B_CPU1_SA_PAR")
	)
	(segment
		(start 64.816228 -257.051048)
		(end 59.25566 -257.051048)
		(width 0.18288)
		(layer "In2.Cu")
		(net "M_B_CPU1_SA_PAR")
	)
	(segment
		(start 93.596714 -249.130312)
		(end 93.882972 -249.295412)
		(width 0.088646)
		(layer "In2.Cu")
		(net "M_B_CPU1_SA_PAR")
	)
	(segment
		(start 51.412394 -260.641592)
		(end 49.166526 -260.641592)
		(width 0.18288)
		(layer "In2.Cu")
		(net "M_B_CPU1_SA_PAR")
	)
	(segment
		(start 51.937666 -259.965444)
		(end 51.604926 -260.44906)
		(width 0.18288)
		(layer "In2.Cu")
		(net "M_B_CPU1_SA_PAR")
	)
	(segment
		(start 94.628716 -249.78868)
		(end 94.487746 -249.92965)
		(width 0.088646)
		(layer "In2.Cu")
		(net "M_B_CPU1_SA_PAR")
	)
	(segment
		(start 53.580284 -258.265168)
		(end 52.710842 -258.846574)
		(width 0.18288)
		(layer "In2.Cu")
		(net "M_B_CPU1_SA_PAR")
	)
	(segment
		(start 93.314012 -247.992138)
		(end 93.409516 -248.77268)
		(width 0.088646)
		(layer "In2.Cu")
		(net "M_B_CPU1_SA_PAR")
	)
	(segment
		(start 82.793332 -252.256036)
		(end 79.497682 -255.551686)
		(width 0.18288)
		(layer "In2.Cu")
		(net "M_B_CPU1_SA_PAR")
	)
	(segment
		(start 86.968076 -252.094238)
		(end 86.577424 -252.256036)
		(width 0.18288)
		(layer "In2.Cu")
		(net "M_B_CPU1_SA_PAR")
	)
	(segment
		(start 49.166526 -260.641592)
		(end 48.42637 -260.336792)
		(width 0.18288)
		(layer "In2.Cu")
		(net "M_B_CPU1_SA_PAR")
	)
	(segment
		(start 71.849996 -255.551686)
		(end 71.4756 -255.695704)
		(width 0.18288)
		(layer "In2.Cu")
		(net "M_B_CPU1_SA_PAR")
	)
	(segment
		(start 52.2097 -259.696712)
		(end 51.937666 -259.965444)
		(width 0.18288)
		(layer "In2.Cu")
		(net "M_B_CPU1_SA_PAR")
	)
	(segment
		(start 94.487746 -249.92965)
		(end 94.487746 -250.114562)
		(width 0.088646)
		(layer "In2.Cu")
		(net "M_B_CPU1_SA_PAR")
	)
	(segment
		(start 93.409516 -248.77268)
		(end 93.409516 -248.806208)
		(width 0.088646)
		(layer "In2.Cu")
		(net "M_B_CPU1_SA_PAR")
	)
	(segment
		(start 71.4756 -255.695704)
		(end 70.879716 -255.925066)
		(width 0.18288)
		(layer "In2.Cu")
		(net "M_B_CPU1_SA_PAR")
	)
	(segment
		(start 70.879716 -255.925066)
		(end 64.816228 -257.051048)
		(width 0.18288)
		(layer "In2.Cu")
		(net "M_B_CPU1_SA_PAR")
	)
	(segment
		(start 93.868748 -251.2822)
		(end 91.907868 -252.094238)
		(width 0.18288)
		(layer "In2.Cu")
		(net "M_B_CPU1_SA_PAR")
	)
	(segment
		(start 52.710842 -258.846574)
		(end 52.466748 -259.08762)
		(width 0.18288)
		(layer "In2.Cu")
		(net "M_B_CPU1_SA_PAR")
	)
	(segment
		(start 94.628716 -249.620278)
		(end 94.628716 -249.78868)
		(width 0.088646)
		(layer "In2.Cu")
		(net "M_B_CPU1_SA_PAR")
	)
	(segment
		(start 48.42637 -260.336792)
		(end 46.964346 -259.366766)
		(width 0.18288)
		(layer "In2.Cu")
		(net "M_B_CPU1_SA_PAR")
	)
	(segment
		(start 91.907868 -252.094238)
		(end 86.968076 -252.094238)
		(width 0.18288)
		(layer "In2.Cu")
		(net "M_B_CPU1_SA_PAR")
	)
	(segment
		(start 94.066614 -249.295666)
		(end 94.066868 -249.295666)
		(width 0.088646)
		(layer "In2.Cu")
		(net "M_B_CPU1_SA_PAR")
	)
	(segment
		(start 86.577424 -252.256036)
		(end 82.793332 -252.256036)
		(width 0.18288)
		(layer "In2.Cu")
		(net "M_B_CPU1_SA_PAR")
	)
	(segment
		(start 94.628462 -249.620024)
		(end 94.628716 -249.620278)
		(width 0.088646)
		(layer "In2.Cu")
		(net "M_B_CPU1_SA_PAR")
	)
	(segment
		(start 79.497682 -255.551686)
		(end 71.849996 -255.551686)
		(width 0.18288)
		(layer "In2.Cu")
		(net "M_B_CPU1_SA_PAR")
	)
	(segment
		(start 52.466748 -259.08762)
		(end 52.2097 -259.696712)
		(width 0.18288)
		(layer "In2.Cu")
		(net "M_B_CPU1_SA_PAR")
	)
	(segment
		(start 94.44101 -249.295666)
		(end 94.441264 -249.29592)
		(width 0.088646)
		(layer "In2.Cu")
		(net "M_B_CPU1_SA_PAR")
	)
	(segment
		(start 94.487746 -250.114562)
		(end 94.487746 -250.663202)
		(width 0.18288)
		(layer "In2.Cu")
		(net "M_B_CPU1_SA_PAR")
	)
	(arc
		(start 93.882972 -249.295412)
		(mid 93.974747 -249.320083)
		(end 94.066614 -249.295666)
		(width 0.088646)
		(layer "In2.Cu")
		(net "M_B_CPU1_SA_PAR")
	)
	(arc
		(start 93.409516 -248.806208)
		(mid 93.45968 -248.993346)
		(end 93.596714 -249.130312)
		(width 0.088646)
		(layer "In2.Cu")
		(net "M_B_CPU1_SA_PAR")
	)
	(arc
		(start 94.441264 -249.29592)
		(mid 94.578309 -249.43288)
		(end 94.628462 -249.620024)
		(width 0.088646)
		(layer "In2.Cu")
		(net "M_B_CPU1_SA_PAR")
	)
	(arc
		(start 94.066868 -249.295666)
		(mid 94.253956 -249.245489)
		(end 94.44101 -249.295666)
		(width 0.088646)
		(layer "In2.Cu")
		(net "M_B_CPU1_SA_PAR")
	)
	(segment
		(start 47.9679 -273.652996)
		(end 47.462948 -273.652996)
		(width 0.20066)
		(layer "F.Cu")
		(net "M_B_CPU1_SA_DQS_DP<9>")
	)
	(segment
		(start 43.151552 -274.077938)
		(end 42.890186 -273.816572)
		(width 0.20066)
		(layer "F.Cu")
		(net "M_B_CPU1_SA_DQS_DP<9>")
	)
	(segment
		(start 49.469802 -273.816572)
		(end 49.208436 -274.077938)
		(width 0.20066)
		(layer "F.Cu")
		(net "M_B_CPU1_SA_DQS_DP<9>")
	)
	(segment
		(start 47.060104 -273.39163)
		(end 44.98213 -273.39163)
		(width 0.1016)
		(layer "F.Cu")
		(net "M_B_CPU1_SA_DQS_DP<9>")
	)
	(segment
		(start 43.908218 -273.655536)
		(end 43.485816 -274.077938)
		(width 0.20066)
		(layer "F.Cu")
		(net "M_B_CPU1_SA_DQS_DP<9>")
	)
	(segment
		(start 49.208436 -274.077938)
		(end 48.603916 -274.077938)
		(width 0.20066)
		(layer "F.Cu")
		(net "M_B_CPU1_SA_DQS_DP<9>")
	)
	(segment
		(start 47.462948 -273.652996)
		(end 47.201836 -273.391884)
		(width 0.20066)
		(layer "F.Cu")
		(net "M_B_CPU1_SA_DQS_DP<9>")
	)
	(segment
		(start 91.074748 -259.895086)
		(end 91.074748 -260.430772)
		(width 0.20066)
		(layer "F.Cu")
		(net "M_B_CPU1_SA_DQS_DP<9>")
	)
	(segment
		(start 91.074494 -259.894832)
		(end 91.074748 -259.895086)
		(width 0.20066)
		(layer "F.Cu")
		(net "M_B_CPU1_SA_DQS_DP<9>")
	)
	(segment
		(start 49.959514 -273.816572)
		(end 49.469802 -273.816572)
		(width 0.20066)
		(layer "F.Cu")
		(net "M_B_CPU1_SA_DQS_DP<9>")
	)
	(segment
		(start 44.537884 -273.386042)
		(end 44.26839 -273.655536)
		(width 0.20066)
		(layer "F.Cu")
		(net "M_B_CPU1_SA_DQS_DP<9>")
	)
	(segment
		(start 44.26839 -273.655536)
		(end 43.908218 -273.655536)
		(width 0.20066)
		(layer "F.Cu")
		(net "M_B_CPU1_SA_DQS_DP<9>")
	)
	(segment
		(start 51.089814 -273.816572)
		(end 49.959514 -273.816572)
		(width 0.20066)
		(layer "F.Cu")
		(net "M_B_CPU1_SA_DQS_DP<9>")
	)
	(segment
		(start 47.060358 -273.391884)
		(end 47.060104 -273.39163)
		(width 0.1016)
		(layer "F.Cu")
		(net "M_B_CPU1_SA_DQS_DP<9>")
	)
	(segment
		(start 44.98213 -273.39163)
		(end 44.74083 -273.39163)
		(width 0.101854)
		(layer "F.Cu")
		(net "M_B_CPU1_SA_DQS_DP<9>")
	)
	(segment
		(start 44.74083 -273.39163)
		(end 44.735242 -273.386042)
		(width 0.101854)
		(layer "F.Cu")
		(net "M_B_CPU1_SA_DQS_DP<9>")
	)
	(segment
		(start 44.735242 -273.386042)
		(end 44.537884 -273.386042)
		(width 0.20066)
		(layer "F.Cu")
		(net "M_B_CPU1_SA_DQS_DP<9>")
	)
	(segment
		(start 43.485816 -274.077938)
		(end 43.151552 -274.077938)
		(width 0.20066)
		(layer "F.Cu")
		(net "M_B_CPU1_SA_DQS_DP<9>")
	)
	(segment
		(start 42.890186 -273.816572)
		(end 42.415714 -273.816572)
		(width 0.20066)
		(layer "F.Cu")
		(net "M_B_CPU1_SA_DQS_DP<9>")
	)
	(segment
		(start 48.603916 -274.077938)
		(end 47.9679 -273.652996)
		(width 0.20066)
		(layer "F.Cu")
		(net "M_B_CPU1_SA_DQS_DP<9>")
	)
	(segment
		(start 47.201836 -273.391884)
		(end 47.060358 -273.391884)
		(width 0.20066)
		(layer "F.Cu")
		(net "M_B_CPU1_SA_DQS_DP<9>")
	)
	(segment
		(start 54.576472 -274.303236)
		(end 54.37632 -274.103084)
		(width 0.16002)
		(layer "In2.Cu")
		(net "M_B_CPU1_SA_DQS_DP<9>")
	)
	(segment
		(start 54.716934 -274.42795)
		(end 54.620414 -274.33143)
		(width 0.18288)
		(layer "In2.Cu")
		(net "M_B_CPU1_SA_DQS_DP<9>")
	)
	(segment
		(start 54.59222 -274.303236)
		(end 54.576472 -274.303236)
		(width 0.16002)
		(layer "In2.Cu")
		(net "M_B_CPU1_SA_DQS_DP<9>")
	)
	(segment
		(start 61.82487 -273.202908)
		(end 61.796676 -273.231102)
		(width 0.16002)
		(layer "In2.Cu")
		(net "M_B_CPU1_SA_DQS_DP<9>")
	)
	(segment
		(start 84.025994 -259.99186)
		(end 83.75015 -259.99186)
		(width 0.088646)
		(layer "In2.Cu")
		(net "M_B_CPU1_SA_DQS_DP<9>")
	)
	(segment
		(start 52.430172 -274.087336)
		(end 52.430172 -274.103084)
		(width 0.16002)
		(layer "In2.Cu")
		(net "M_B_CPU1_SA_DQS_DP<9>")
	)
	(segment
		(start 61.796676 -273.247358)
		(end 61.597032 -273.447002)
		(width 0.16002)
		(layer "In2.Cu")
		(net "M_B_CPU1_SA_DQS_DP<9>")
	)
	(segment
		(start 54.620414 -274.33143)
		(end 54.59222 -274.303236)
		(width 0.16002)
		(layer "In2.Cu")
		(net "M_B_CPU1_SA_DQS_DP<9>")
	)
	(segment
		(start 90.423492 -259.94487)
		(end 90.402156 -259.932678)
		(width 0.088646)
		(layer "In2.Cu")
		(net "M_B_CPU1_SA_DQS_DP<9>")
	)
	(segment
		(start 73.935844 -264.663682)
		(end 66.711068 -271.88541)
		(width 0.18288)
		(layer "In2.Cu")
		(net "M_B_CPU1_SA_DQS_DP<9>")
	)
	(segment
		(start 58.448194 -273.209004)
		(end 58.26506 -273.02587)
		(width 0.18288)
		(layer "In2.Cu")
		(net "M_B_CPU1_SA_DQS_DP<9>")
	)
	(segment
		(start 63.14694 -272.46453)
		(end 62.563248 -272.46453)
		(width 0.18288)
		(layer "In2.Cu")
		(net "M_B_CPU1_SA_DQS_DP<9>")
	)
	(segment
		(start 56.53024 -273.252946)
		(end 56.330088 -273.453098)
		(width 0.16002)
		(layer "In2.Cu")
		(net "M_B_CPU1_SA_DQS_DP<9>")
	)
	(segment
		(start 58.67654 -273.453098)
		(end 58.476388 -273.252946)
		(width 0.16002)
		(layer "In2.Cu")
		(net "M_B_CPU1_SA_DQS_DP<9>")
	)
	(segment
		(start 51.930554 -274.36699)
		(end 51.56073 -273.997166)
		(width 0.18288)
		(layer "In2.Cu")
		(net "M_B_CPU1_SA_DQS_DP<9>")
	)
	(segment
		(start 66.236088 -271.75333)
		(end 66.22034 -271.75333)
		(width 0.16002)
		(layer "In2.Cu")
		(net "M_B_CPU1_SA_DQS_DP<9>")
	)
	(segment
		(start 52.150518 -274.36699)
		(end 51.930554 -274.36699)
		(width 0.18288)
		(layer "In2.Cu")
		(net "M_B_CPU1_SA_DQS_DP<9>")
	)
	(segment
		(start 65.80886 -271.326102)
		(end 64.285368 -271.326102)
		(width 0.18288)
		(layer "In2.Cu")
		(net "M_B_CPU1_SA_DQS_DP<9>")
	)
	(segment
		(start 66.020188 -271.53743)
		(end 65.991994 -271.509236)
		(width 0.16002)
		(layer "In2.Cu")
		(net "M_B_CPU1_SA_DQS_DP<9>")
	)
	(segment
		(start 83.75015 -259.99186)
		(end 81.708244 -262.033766)
		(width 0.088646)
		(layer "In2.Cu")
		(net "M_B_CPU1_SA_DQS_DP<9>")
	)
	(segment
		(start 56.31434 -273.453098)
		(end 56.286146 -273.481292)
		(width 0.16002)
		(layer "In2.Cu")
		(net "M_B_CPU1_SA_DQS_DP<9>")
	)
	(segment
		(start 58.720482 -273.481292)
		(end 58.692288 -273.453098)
		(width 0.16002)
		(layer "In2.Cu")
		(net "M_B_CPU1_SA_DQS_DP<9>")
	)
	(segment
		(start 58.900822 -273.661632)
		(end 58.720482 -273.481292)
		(width 0.18288)
		(layer "In2.Cu")
		(net "M_B_CPU1_SA_DQS_DP<9>")
	)
	(segment
		(start 61.552582 -273.475196)
		(end 61.366146 -273.661632)
		(width 0.18288)
		(layer "In2.Cu")
		(net "M_B_CPU1_SA_DQS_DP<9>")
	)
	(segment
		(start 66.020188 -271.553178)
		(end 66.020188 -271.53743)
		(width 0.16002)
		(layer "In2.Cu")
		(net "M_B_CPU1_SA_DQS_DP<9>")
	)
	(segment
		(start 90.76182 -260.430772)
		(end 90.696288 -260.36524)
		(width 0.088646)
		(layer "In2.Cu")
		(net "M_B_CPU1_SA_DQS_DP<9>")
	)
	(segment
		(start 81.022698 -262.033766)
		(end 78.409546 -262.033766)
		(width 0.18288)
		(layer "In2.Cu")
		(net "M_B_CPU1_SA_DQS_DP<9>")
	)
	(segment
		(start 81.708244 -262.033766)
		(end 81.022698 -262.033766)
		(width 0.088646)
		(layer "In2.Cu")
		(net "M_B_CPU1_SA_DQS_DP<9>")
	)
	(segment
		(start 66.368168 -271.88541)
		(end 66.264282 -271.781524)
		(width 0.18288)
		(layer "In2.Cu")
		(net "M_B_CPU1_SA_DQS_DP<9>")
	)
	(segment
		(start 64.102234 -271.509236)
		(end 64.07404 -271.53743)
		(width 0.16002)
		(layer "In2.Cu")
		(net "M_B_CPU1_SA_DQS_DP<9>")
	)
	(segment
		(start 55.890414 -273.877024)
		(end 55.544974 -273.877024)
		(width 0.18288)
		(layer "In2.Cu")
		(net "M_B_CPU1_SA_DQS_DP<9>")
	)
	(segment
		(start 63.873888 -271.75333)
		(end 63.85814 -271.75333)
		(width 0.16002)
		(layer "In2.Cu")
		(net "M_B_CPU1_SA_DQS_DP<9>")
	)
	(segment
		(start 59.80303 -273.389852)
		(end 59.449462 -273.389852)
		(width 0.18288)
		(layer "In2.Cu")
		(net "M_B_CPU1_SA_DQS_DP<9>")
	)
	(segment
		(start 78.409546 -262.033766)
		(end 77.090778 -263.352534)
		(width 0.18288)
		(layer "In2.Cu")
		(net "M_B_CPU1_SA_DQS_DP<9>")
	)
	(segment
		(start 59.177682 -273.661632)
		(end 58.900822 -273.661632)
		(width 0.18288)
		(layer "In2.Cu")
		(net "M_B_CPU1_SA_DQS_DP<9>")
	)
	(segment
		(start 58.692288 -273.453098)
		(end 58.67654 -273.453098)
		(width 0.16002)
		(layer "In2.Cu")
		(net "M_B_CPU1_SA_DQS_DP<9>")
	)
	(segment
		(start 77.090778 -263.352534)
		(end 73.935844 -264.663682)
		(width 0.18288)
		(layer "In2.Cu")
		(net "M_B_CPU1_SA_DQS_DP<9>")
	)
	(segment
		(start 52.23002 -274.303236)
		(end 52.214272 -274.303236)
		(width 0.16002)
		(layer "In2.Cu")
		(net "M_B_CPU1_SA_DQS_DP<9>")
	)
	(segment
		(start 59.449462 -273.389852)
		(end 59.177682 -273.661632)
		(width 0.18288)
		(layer "In2.Cu")
		(net "M_B_CPU1_SA_DQS_DP<9>")
	)
	(segment
		(start 54.348126 -274.059142)
		(end 54.165754 -273.87677)
		(width 0.18288)
		(layer "In2.Cu")
		(net "M_B_CPU1_SA_DQS_DP<9>")
	)
	(segment
		(start 61.597032 -273.447002)
		(end 61.580776 -273.447002)
		(width 0.16002)
		(layer "In2.Cu")
		(net "M_B_CPU1_SA_DQS_DP<9>")
	)
	(segment
		(start 64.07404 -271.553178)
		(end 63.873888 -271.75333)
		(width 0.16002)
		(layer "In2.Cu")
		(net "M_B_CPU1_SA_DQS_DP<9>")
	)
	(segment
		(start 64.285368 -271.326102)
		(end 64.102234 -271.509236)
		(width 0.18288)
		(layer "In2.Cu")
		(net "M_B_CPU1_SA_DQS_DP<9>")
	)
	(segment
		(start 56.286146 -273.481292)
		(end 55.890414 -273.877024)
		(width 0.18288)
		(layer "In2.Cu")
		(net "M_B_CPU1_SA_DQS_DP<9>")
	)
	(segment
		(start 54.994048 -274.42795)
		(end 54.716934 -274.42795)
		(width 0.18288)
		(layer "In2.Cu")
		(net "M_B_CPU1_SA_DQS_DP<9>")
	)
	(segment
		(start 60.07481 -273.661632)
		(end 59.80303 -273.389852)
		(width 0.18288)
		(layer "In2.Cu")
		(net "M_B_CPU1_SA_DQS_DP<9>")
	)
	(segment
		(start 64.07404 -271.53743)
		(end 64.07404 -271.553178)
		(width 0.16002)
		(layer "In2.Cu")
		(net "M_B_CPU1_SA_DQS_DP<9>")
	)
	(segment
		(start 66.264282 -271.781524)
		(end 66.236088 -271.75333)
		(width 0.16002)
		(layer "In2.Cu")
		(net "M_B_CPU1_SA_DQS_DP<9>")
	)
	(segment
		(start 66.22034 -271.75333)
		(end 66.020188 -271.553178)
		(width 0.16002)
		(layer "In2.Cu")
		(net "M_B_CPU1_SA_DQS_DP<9>")
	)
	(segment
		(start 61.796676 -273.231102)
		(end 61.796676 -273.247358)
		(width 0.16002)
		(layer "In2.Cu")
		(net "M_B_CPU1_SA_DQS_DP<9>")
	)
	(segment
		(start 54.165754 -273.87677)
		(end 52.640738 -273.87677)
		(width 0.18288)
		(layer "In2.Cu")
		(net "M_B_CPU1_SA_DQS_DP<9>")
	)
	(segment
		(start 56.330088 -273.453098)
		(end 56.31434 -273.453098)
		(width 0.16002)
		(layer "In2.Cu")
		(net "M_B_CPU1_SA_DQS_DP<9>")
	)
	(segment
		(start 65.991994 -271.509236)
		(end 65.80886 -271.326102)
		(width 0.18288)
		(layer "In2.Cu")
		(net "M_B_CPU1_SA_DQS_DP<9>")
	)
	(segment
		(start 63.85814 -271.75333)
		(end 63.829946 -271.781524)
		(width 0.16002)
		(layer "In2.Cu")
		(net "M_B_CPU1_SA_DQS_DP<9>")
	)
	(segment
		(start 52.186078 -274.33143)
		(end 52.150518 -274.36699)
		(width 0.18288)
		(layer "In2.Cu")
		(net "M_B_CPU1_SA_DQS_DP<9>")
	)
	(segment
		(start 51.270408 -273.997166)
		(end 51.089814 -273.816572)
		(width 0.18288)
		(layer "In2.Cu")
		(net "M_B_CPU1_SA_DQS_DP<9>")
	)
	(segment
		(start 58.26506 -273.02587)
		(end 56.741568 -273.02587)
		(width 0.18288)
		(layer "In2.Cu")
		(net "M_B_CPU1_SA_DQS_DP<9>")
	)
	(segment
		(start 52.430172 -274.103084)
		(end 52.23002 -274.303236)
		(width 0.16002)
		(layer "In2.Cu")
		(net "M_B_CPU1_SA_DQS_DP<9>")
	)
	(segment
		(start 56.558434 -273.209004)
		(end 56.53024 -273.237198)
		(width 0.16002)
		(layer "In2.Cu")
		(net "M_B_CPU1_SA_DQS_DP<9>")
	)
	(segment
		(start 51.56073 -273.997166)
		(end 51.270408 -273.997166)
		(width 0.18288)
		(layer "In2.Cu")
		(net "M_B_CPU1_SA_DQS_DP<9>")
	)
	(segment
		(start 58.476388 -273.252946)
		(end 58.476388 -273.237198)
		(width 0.16002)
		(layer "In2.Cu")
		(net "M_B_CPU1_SA_DQS_DP<9>")
	)
	(segment
		(start 61.366146 -273.661632)
		(end 60.07481 -273.661632)
		(width 0.18288)
		(layer "In2.Cu")
		(net "M_B_CPU1_SA_DQS_DP<9>")
	)
	(segment
		(start 90.402156 -259.932678)
		(end 90.402664 -259.932678)
		(width 0.088646)
		(layer "In2.Cu")
		(net "M_B_CPU1_SA_DQS_DP<9>")
	)
	(segment
		(start 91.074748 -260.430772)
		(end 90.76182 -260.430772)
		(width 0.088646)
		(layer "In2.Cu")
		(net "M_B_CPU1_SA_DQS_DP<9>")
	)
	(segment
		(start 52.458366 -274.059142)
		(end 52.430172 -274.087336)
		(width 0.16002)
		(layer "In2.Cu")
		(net "M_B_CPU1_SA_DQS_DP<9>")
	)
	(segment
		(start 58.476388 -273.237198)
		(end 58.448194 -273.209004)
		(width 0.16002)
		(layer "In2.Cu")
		(net "M_B_CPU1_SA_DQS_DP<9>")
	)
	(segment
		(start 89.477596 -259.941314)
		(end 89.462864 -259.932678)
		(width 0.088646)
		(layer "In2.Cu")
		(net "M_B_CPU1_SA_DQS_DP<9>")
	)
	(segment
		(start 52.640738 -273.87677)
		(end 52.458366 -274.059142)
		(width 0.18288)
		(layer "In2.Cu")
		(net "M_B_CPU1_SA_DQS_DP<9>")
	)
	(segment
		(start 52.214272 -274.303236)
		(end 52.186078 -274.33143)
		(width 0.16002)
		(layer "In2.Cu")
		(net "M_B_CPU1_SA_DQS_DP<9>")
	)
	(segment
		(start 63.829946 -271.781524)
		(end 63.14694 -272.46453)
		(width 0.18288)
		(layer "In2.Cu")
		(net "M_B_CPU1_SA_DQS_DP<9>")
	)
	(segment
		(start 56.741568 -273.02587)
		(end 56.558434 -273.209004)
		(width 0.18288)
		(layer "In2.Cu")
		(net "M_B_CPU1_SA_DQS_DP<9>")
	)
	(segment
		(start 61.580776 -273.447002)
		(end 61.552582 -273.475196)
		(width 0.16002)
		(layer "In2.Cu")
		(net "M_B_CPU1_SA_DQS_DP<9>")
	)
	(segment
		(start 66.711068 -271.88541)
		(end 66.368168 -271.88541)
		(width 0.18288)
		(layer "In2.Cu")
		(net "M_B_CPU1_SA_DQS_DP<9>")
	)
	(segment
		(start 56.53024 -273.237198)
		(end 56.53024 -273.252946)
		(width 0.16002)
		(layer "In2.Cu")
		(net "M_B_CPU1_SA_DQS_DP<9>")
	)
	(segment
		(start 62.563248 -272.46453)
		(end 61.82487 -273.202908)
		(width 0.18288)
		(layer "In2.Cu")
		(net "M_B_CPU1_SA_DQS_DP<9>")
	)
	(segment
		(start 55.544974 -273.877024)
		(end 54.994048 -274.42795)
		(width 0.18288)
		(layer "In2.Cu")
		(net "M_B_CPU1_SA_DQS_DP<9>")
	)
	(segment
		(start 54.37632 -274.103084)
		(end 54.37632 -274.087336)
		(width 0.16002)
		(layer "In2.Cu")
		(net "M_B_CPU1_SA_DQS_DP<9>")
	)
	(segment
		(start 54.37632 -274.087336)
		(end 54.348126 -274.059142)
		(width 0.16002)
		(layer "In2.Cu")
		(net "M_B_CPU1_SA_DQS_DP<9>")
	)
	(arc
		(start 87.972392 -259.941314)
		(mid 87.785194 -259.991457)
		(end 87.597996 -259.941314)
		(width 0.088646)
		(layer "In2.Cu")
		(net "M_B_CPU1_SA_DQS_DP<9>")
	)
	(arc
		(start 89.851992 -259.941314)
		(mid 89.664794 -259.991457)
		(end 89.477596 -259.941314)
		(width 0.088646)
		(layer "In2.Cu")
		(net "M_B_CPU1_SA_DQS_DP<9>")
	)
	(arc
		(start 87.597996 -259.941314)
		(mid 87.315294 -259.865538)
		(end 87.032592 -259.941314)
		(width 0.088646)
		(layer "In2.Cu")
		(net "M_B_CPU1_SA_DQS_DP<9>")
	)
	(arc
		(start 84.778596 -259.941314)
		(mid 84.495894 -259.865538)
		(end 84.213192 -259.941314)
		(width 0.088646)
		(layer "In2.Cu")
		(net "M_B_CPU1_SA_DQS_DP<9>")
	)
	(arc
		(start 90.696288 -260.36524)
		(mid 90.609044 -260.123152)
		(end 90.423492 -259.94487)
		(width 0.088646)
		(layer "In2.Cu")
		(net "M_B_CPU1_SA_DQS_DP<9>")
	)
	(arc
		(start 90.402664 -259.932678)
		(mid 90.126189 -259.865358)
		(end 89.851992 -259.941314)
		(width 0.088646)
		(layer "In2.Cu")
		(net "M_B_CPU1_SA_DQS_DP<9>")
	)
	(arc
		(start 88.537796 -259.941314)
		(mid 88.255094 -259.865538)
		(end 87.972392 -259.941314)
		(width 0.088646)
		(layer "In2.Cu")
		(net "M_B_CPU1_SA_DQS_DP<9>")
	)
	(arc
		(start 85.152992 -259.941314)
		(mid 84.965794 -259.991457)
		(end 84.778596 -259.941314)
		(width 0.088646)
		(layer "In2.Cu")
		(net "M_B_CPU1_SA_DQS_DP<9>")
	)
	(arc
		(start 88.912192 -259.941314)
		(mid 88.724994 -259.991457)
		(end 88.537796 -259.941314)
		(width 0.088646)
		(layer "In2.Cu")
		(net "M_B_CPU1_SA_DQS_DP<9>")
	)
	(arc
		(start 87.032592 -259.941314)
		(mid 86.845394 -259.991457)
		(end 86.658196 -259.941314)
		(width 0.088646)
		(layer "In2.Cu")
		(net "M_B_CPU1_SA_DQS_DP<9>")
	)
	(arc
		(start 89.462864 -259.932678)
		(mid 89.186389 -259.865358)
		(end 88.912192 -259.941314)
		(width 0.088646)
		(layer "In2.Cu")
		(net "M_B_CPU1_SA_DQS_DP<9>")
	)
	(arc
		(start 86.092792 -259.941314)
		(mid 85.905594 -259.991457)
		(end 85.718396 -259.941314)
		(width 0.088646)
		(layer "In2.Cu")
		(net "M_B_CPU1_SA_DQS_DP<9>")
	)
	(arc
		(start 85.718396 -259.941314)
		(mid 85.435694 -259.865538)
		(end 85.152992 -259.941314)
		(width 0.088646)
		(layer "In2.Cu")
		(net "M_B_CPU1_SA_DQS_DP<9>")
	)
	(arc
		(start 84.213192 -259.941314)
		(mid 84.122916 -259.978888)
		(end 84.025994 -259.99186)
		(width 0.088646)
		(layer "In2.Cu")
		(net "M_B_CPU1_SA_DQS_DP<9>")
	)
	(arc
		(start 86.658196 -259.941314)
		(mid 86.375494 -259.865538)
		(end 86.092792 -259.941314)
		(width 0.088646)
		(layer "In2.Cu")
		(net "M_B_CPU1_SA_DQS_DP<9>")
	)
	(segment
		(start 44.26839 -283.00553)
		(end 44.537884 -282.736036)
		(width 0.20066)
		(layer "F.Cu")
		(net "M_B_CPU1_SA_DQS_DP<8>")
	)
	(segment
		(start 43.151552 -283.427932)
		(end 43.485816 -283.427932)
		(width 0.20066)
		(layer "F.Cu")
		(net "M_B_CPU1_SA_DQS_DP<8>")
	)
	(segment
		(start 51.08956 -283.166566)
		(end 49.959514 -283.166566)
		(width 0.20066)
		(layer "F.Cu")
		(net "M_B_CPU1_SA_DQS_DP<8>")
	)
	(segment
		(start 51.089814 -283.16682)
		(end 51.08956 -283.166566)
		(width 0.20066)
		(layer "F.Cu")
		(net "M_B_CPU1_SA_DQS_DP<8>")
	)
	(segment
		(start 43.908218 -283.00553)
		(end 44.26839 -283.00553)
		(width 0.20066)
		(layer "F.Cu")
		(net "M_B_CPU1_SA_DQS_DP<8>")
	)
	(segment
		(start 44.735242 -282.736036)
		(end 44.74083 -282.741624)
		(width 0.101854)
		(layer "F.Cu")
		(net "M_B_CPU1_SA_DQS_DP<8>")
	)
	(segment
		(start 48.603916 -283.427932)
		(end 49.208436 -283.427932)
		(width 0.20066)
		(layer "F.Cu")
		(net "M_B_CPU1_SA_DQS_DP<8>")
	)
	(segment
		(start 44.98213 -282.741624)
		(end 47.060104 -282.741624)
		(width 0.1016)
		(layer "F.Cu")
		(net "M_B_CPU1_SA_DQS_DP<8>")
	)
	(segment
		(start 49.469802 -283.166566)
		(end 49.959514 -283.166566)
		(width 0.20066)
		(layer "F.Cu")
		(net "M_B_CPU1_SA_DQS_DP<8>")
	)
	(segment
		(start 43.485816 -283.427932)
		(end 43.908218 -283.00553)
		(width 0.20066)
		(layer "F.Cu")
		(net "M_B_CPU1_SA_DQS_DP<8>")
	)
	(segment
		(start 47.462948 -283.00299)
		(end 47.9679 -283.00299)
		(width 0.20066)
		(layer "F.Cu")
		(net "M_B_CPU1_SA_DQS_DP<8>")
	)
	(segment
		(start 44.74083 -282.741624)
		(end 44.98213 -282.741624)
		(width 0.101854)
		(layer "F.Cu")
		(net "M_B_CPU1_SA_DQS_DP<8>")
	)
	(segment
		(start 47.060104 -282.741624)
		(end 47.060358 -282.741878)
		(width 0.1016)
		(layer "F.Cu")
		(net "M_B_CPU1_SA_DQS_DP<8>")
	)
	(segment
		(start 44.537884 -282.736036)
		(end 44.735242 -282.736036)
		(width 0.20066)
		(layer "F.Cu")
		(net "M_B_CPU1_SA_DQS_DP<8>")
	)
	(segment
		(start 42.890186 -283.166566)
		(end 43.151552 -283.427932)
		(width 0.20066)
		(layer "F.Cu")
		(net "M_B_CPU1_SA_DQS_DP<8>")
	)
	(segment
		(start 93.424248 -262.336534)
		(end 93.424248 -262.87222)
		(width 0.20066)
		(layer "F.Cu")
		(net "M_B_CPU1_SA_DQS_DP<8>")
	)
	(segment
		(start 93.424248 -262.87222)
		(end 93.423994 -262.872474)
		(width 0.20066)
		(layer "F.Cu")
		(net "M_B_CPU1_SA_DQS_DP<8>")
	)
	(segment
		(start 49.208436 -283.427932)
		(end 49.469802 -283.166566)
		(width 0.20066)
		(layer "F.Cu")
		(net "M_B_CPU1_SA_DQS_DP<8>")
	)
	(segment
		(start 47.201836 -282.741878)
		(end 47.462948 -283.00299)
		(width 0.20066)
		(layer "F.Cu")
		(net "M_B_CPU1_SA_DQS_DP<8>")
	)
	(segment
		(start 47.060358 -282.741878)
		(end 47.201836 -282.741878)
		(width 0.20066)
		(layer "F.Cu")
		(net "M_B_CPU1_SA_DQS_DP<8>")
	)
	(segment
		(start 47.9679 -283.00299)
		(end 48.603916 -283.427932)
		(width 0.20066)
		(layer "F.Cu")
		(net "M_B_CPU1_SA_DQS_DP<8>")
	)
	(segment
		(start 42.415714 -283.166566)
		(end 42.890186 -283.166566)
		(width 0.20066)
		(layer "F.Cu")
		(net "M_B_CPU1_SA_DQS_DP<8>")
	)
	(segment
		(start 83.213448 -262.52043)
		(end 82.879946 -262.52043)
		(width 0.088646)
		(layer "In4.Cu")
		(net "M_B_CPU1_SA_DQS_DP<8>")
	)
	(segment
		(start 60.525914 -278.387048)
		(end 60.090812 -278.82215)
		(width 0.18288)
		(layer "In4.Cu")
		(net "M_B_CPU1_SA_DQS_DP<8>")
	)
	(segment
		(start 83.743292 -262.383016)
		(end 83.743038 -262.38327)
		(width 0.088646)
		(layer "In4.Cu")
		(net "M_B_CPU1_SA_DQS_DP<8>")
	)
	(segment
		(start 70.751192 -269.88262)
		(end 70.751192 -270.058642)
		(width 0.18288)
		(layer "In4.Cu")
		(net "M_B_CPU1_SA_DQS_DP<8>")
	)
	(segment
		(start 76.075286 -264.734548)
		(end 75.899264 -264.734548)
		(width 0.18288)
		(layer "In4.Cu")
		(net "M_B_CPU1_SA_DQS_DP<8>")
	)
	(segment
		(start 68.847208 -271.786604)
		(end 68.847208 -271.962626)
		(width 0.18288)
		(layer "In4.Cu")
		(net "M_B_CPU1_SA_DQS_DP<8>")
	)
	(segment
		(start 56.304942 -279.579578)
		(end 55.367174 -280.517092)
		(width 0.18288)
		(layer "In4.Cu")
		(net "M_B_CPU1_SA_DQS_DP<8>")
	)
	(segment
		(start 77.027532 -263.782556)
		(end 76.851256 -263.782556)
		(width 0.18288)
		(layer "In4.Cu")
		(net "M_B_CPU1_SA_DQS_DP<8>")
	)
	(segment
		(start 58.263028 -279.579578)
		(end 56.304942 -279.579578)
		(width 0.18288)
		(layer "In4.Cu")
		(net "M_B_CPU1_SA_DQS_DP<8>")
	)
	(segment
		(start 62.29858 -277.029926)
		(end 61.589158 -277.323804)
		(width 0.18288)
		(layer "In4.Cu")
		(net "M_B_CPU1_SA_DQS_DP<8>")
	)
	(segment
		(start 63.33109 -275.046948)
		(end 62.658498 -276.670008)
		(width 0.18288)
		(layer "In4.Cu")
		(net "M_B_CPU1_SA_DQS_DP<8>")
	)
	(segment
		(start 75.899264 -264.734548)
		(end 75.511152 -265.12266)
		(width 0.18288)
		(layer "In4.Cu")
		(net "M_B_CPU1_SA_DQS_DP<8>")
	)
	(segment
		(start 61.090302 -277.82266)
		(end 60.91428 -277.82266)
		(width 0.18288)
		(layer "In4.Cu")
		(net "M_B_CPU1_SA_DQS_DP<8>")
	)
	(segment
		(start 71.703184 -268.930628)
		(end 71.703184 -269.10665)
		(width 0.18288)
		(layer "In4.Cu")
		(net "M_B_CPU1_SA_DQS_DP<8>")
	)
	(segment
		(start 75.511152 -265.298682)
		(end 75.123294 -265.68654)
		(width 0.18288)
		(layer "In4.Cu")
		(net "M_B_CPU1_SA_DQS_DP<8>")
	)
	(segment
		(start 74.171302 -266.638532)
		(end 73.99528 -266.638532)
		(width 0.18288)
		(layer "In4.Cu")
		(net "M_B_CPU1_SA_DQS_DP<8>")
	)
	(segment
		(start 76.463144 -264.34669)
		(end 76.075286 -264.734548)
		(width 0.18288)
		(layer "In4.Cu")
		(net "M_B_CPU1_SA_DQS_DP<8>")
	)
	(segment
		(start 61.589158 -277.323804)
		(end 61.090302 -277.82266)
		(width 0.18288)
		(layer "In4.Cu")
		(net "M_B_CPU1_SA_DQS_DP<8>")
	)
	(segment
		(start 92.81922 -262.41248)
		(end 92.761054 -262.379714)
		(width 0.088646)
		(layer "In4.Cu")
		(net "M_B_CPU1_SA_DQS_DP<8>")
	)
	(segment
		(start 83.300316 -262.433562)
		(end 83.213448 -262.52043)
		(width 0.088646)
		(layer "In4.Cu")
		(net "M_B_CPU1_SA_DQS_DP<8>")
	)
	(segment
		(start 64.899032 -274.21967)
		(end 63.634874 -274.743164)
		(width 0.18288)
		(layer "In4.Cu")
		(net "M_B_CPU1_SA_DQS_DP<8>")
	)
	(segment
		(start 72.655176 -267.978636)
		(end 72.655176 -268.154658)
		(width 0.18288)
		(layer "In4.Cu")
		(net "M_B_CPU1_SA_DQS_DP<8>")
	)
	(segment
		(start 75.123294 -265.68654)
		(end 74.947272 -265.68654)
		(width 0.18288)
		(layer "In4.Cu")
		(net "M_B_CPU1_SA_DQS_DP<8>")
	)
	(segment
		(start 62.658498 -276.670008)
		(end 62.29858 -277.029926)
		(width 0.18288)
		(layer "In4.Cu")
		(net "M_B_CPU1_SA_DQS_DP<8>")
	)
	(segment
		(start 71.139304 -269.494508)
		(end 70.751192 -269.88262)
		(width 0.18288)
		(layer "In4.Cu")
		(net "M_B_CPU1_SA_DQS_DP<8>")
	)
	(segment
		(start 89.011506 -262.385302)
		(end 89.00795 -262.383016)
		(width 0.088646)
		(layer "In4.Cu")
		(net "M_B_CPU1_SA_DQS_DP<8>")
	)
	(segment
		(start 55.367174 -280.517092)
		(end 54.856126 -281.7495)
		(width 0.18288)
		(layer "In4.Cu")
		(net "M_B_CPU1_SA_DQS_DP<8>")
	)
	(segment
		(start 54.626002 -281.979624)
		(end 53.821838 -282.312618)
		(width 0.18288)
		(layer "In4.Cu")
		(net "M_B_CPU1_SA_DQS_DP<8>")
	)
	(segment
		(start 71.315326 -269.494508)
		(end 71.139304 -269.494508)
		(width 0.18288)
		(layer "In4.Cu")
		(net "M_B_CPU1_SA_DQS_DP<8>")
	)
	(segment
		(start 71.703184 -269.10665)
		(end 71.315326 -269.494508)
		(width 0.18288)
		(layer "In4.Cu")
		(net "M_B_CPU1_SA_DQS_DP<8>")
	)
	(segment
		(start 54.856126 -281.7495)
		(end 54.626002 -281.979624)
		(width 0.18288)
		(layer "In4.Cu")
		(net "M_B_CPU1_SA_DQS_DP<8>")
	)
	(segment
		(start 82.820256 -262.46074)
		(end 82.783934 -262.46074)
		(width 0.088646)
		(layer "In4.Cu")
		(net "M_B_CPU1_SA_DQS_DP<8>")
	)
	(segment
		(start 74.55916 -266.250674)
		(end 74.171302 -266.638532)
		(width 0.18288)
		(layer "In4.Cu")
		(net "M_B_CPU1_SA_DQS_DP<8>")
	)
	(segment
		(start 60.525914 -278.211026)
		(end 60.525914 -278.387048)
		(width 0.18288)
		(layer "In4.Cu")
		(net "M_B_CPU1_SA_DQS_DP<8>")
	)
	(segment
		(start 75.511152 -265.12266)
		(end 75.511152 -265.298682)
		(width 0.18288)
		(layer "In4.Cu")
		(net "M_B_CPU1_SA_DQS_DP<8>")
	)
	(segment
		(start 74.55916 -266.074652)
		(end 74.55916 -266.250674)
		(width 0.18288)
		(layer "In4.Cu")
		(net "M_B_CPU1_SA_DQS_DP<8>")
	)
	(segment
		(start 76.851256 -263.782556)
		(end 76.463144 -264.170668)
		(width 0.18288)
		(layer "In4.Cu")
		(net "M_B_CPU1_SA_DQS_DP<8>")
	)
	(segment
		(start 76.463144 -264.170668)
		(end 76.463144 -264.34669)
		(width 0.18288)
		(layer "In4.Cu")
		(net "M_B_CPU1_SA_DQS_DP<8>")
	)
	(segment
		(start 73.99528 -266.638532)
		(end 73.607168 -267.026644)
		(width 0.18288)
		(layer "In4.Cu")
		(net "M_B_CPU1_SA_DQS_DP<8>")
	)
	(segment
		(start 90.893138 -262.386318)
		(end 90.881454 -262.379714)
		(width 0.088646)
		(layer "In4.Cu")
		(net "M_B_CPU1_SA_DQS_DP<8>")
	)
	(segment
		(start 70.751192 -270.058642)
		(end 70.363334 -270.4465)
		(width 0.18288)
		(layer "In4.Cu")
		(net "M_B_CPU1_SA_DQS_DP<8>")
	)
	(segment
		(start 73.607168 -267.026644)
		(end 73.607168 -267.202666)
		(width 0.18288)
		(layer "In4.Cu")
		(net "M_B_CPU1_SA_DQS_DP<8>")
	)
	(segment
		(start 53.821838 -282.312618)
		(end 52.653184 -283.481272)
		(width 0.18288)
		(layer "In4.Cu")
		(net "M_B_CPU1_SA_DQS_DP<8>")
	)
	(segment
		(start 73.607168 -267.202666)
		(end 73.21931 -267.590524)
		(width 0.18288)
		(layer "In4.Cu")
		(net "M_B_CPU1_SA_DQS_DP<8>")
	)
	(segment
		(start 69.7992 -271.010634)
		(end 69.411342 -271.398492)
		(width 0.18288)
		(layer "In4.Cu")
		(net "M_B_CPU1_SA_DQS_DP<8>")
	)
	(segment
		(start 82.783934 -262.46074)
		(end 79.669386 -262.46074)
		(width 0.18288)
		(layer "In4.Cu")
		(net "M_B_CPU1_SA_DQS_DP<8>")
	)
	(segment
		(start 51.843686 -283.437076)
		(end 51.36007 -283.437076)
		(width 0.18288)
		(layer "In4.Cu")
		(net "M_B_CPU1_SA_DQS_DP<8>")
	)
	(segment
		(start 79.669386 -262.46074)
		(end 77.415136 -263.394698)
		(width 0.18288)
		(layer "In4.Cu")
		(net "M_B_CPU1_SA_DQS_DP<8>")
	)
	(segment
		(start 88.452706 -262.37692)
		(end 88.442292 -262.383016)
		(width 0.088646)
		(layer "In4.Cu")
		(net "M_B_CPU1_SA_DQS_DP<8>")
	)
	(segment
		(start 60.91428 -277.82266)
		(end 60.525914 -278.211026)
		(width 0.18288)
		(layer "In4.Cu")
		(net "M_B_CPU1_SA_DQS_DP<8>")
	)
	(segment
		(start 72.091296 -268.542516)
		(end 71.703184 -268.930628)
		(width 0.18288)
		(layer "In4.Cu")
		(net "M_B_CPU1_SA_DQS_DP<8>")
	)
	(segment
		(start 67.785742 -273.024092)
		(end 65.63614 -273.914362)
		(width 0.18288)
		(layer "In4.Cu")
		(net "M_B_CPU1_SA_DQS_DP<8>")
	)
	(segment
		(start 65.473326 -273.847052)
		(end 64.966342 -274.056856)
		(width 0.18288)
		(layer "In4.Cu")
		(net "M_B_CPU1_SA_DQS_DP<8>")
	)
	(segment
		(start 72.267318 -268.542516)
		(end 72.091296 -268.542516)
		(width 0.18288)
		(layer "In4.Cu")
		(net "M_B_CPU1_SA_DQS_DP<8>")
	)
	(segment
		(start 69.23532 -271.398492)
		(end 68.847208 -271.786604)
		(width 0.18288)
		(layer "In4.Cu")
		(net "M_B_CPU1_SA_DQS_DP<8>")
	)
	(segment
		(start 77.415136 -263.394698)
		(end 77.027532 -263.782556)
		(width 0.18288)
		(layer "In4.Cu")
		(net "M_B_CPU1_SA_DQS_DP<8>")
	)
	(segment
		(start 70.363334 -270.4465)
		(end 70.187312 -270.4465)
		(width 0.18288)
		(layer "In4.Cu")
		(net "M_B_CPU1_SA_DQS_DP<8>")
	)
	(segment
		(start 52.38623 -283.591762)
		(end 51.998372 -283.591762)
		(width 0.18288)
		(layer "In4.Cu")
		(net "M_B_CPU1_SA_DQS_DP<8>")
	)
	(segment
		(start 65.63614 -273.914362)
		(end 65.473326 -273.847052)
		(width 0.18288)
		(layer "In4.Cu")
		(net "M_B_CPU1_SA_DQS_DP<8>")
	)
	(segment
		(start 72.655176 -268.154658)
		(end 72.267318 -268.542516)
		(width 0.18288)
		(layer "In4.Cu")
		(net "M_B_CPU1_SA_DQS_DP<8>")
	)
	(segment
		(start 64.966342 -274.056856)
		(end 64.899032 -274.21967)
		(width 0.18288)
		(layer "In4.Cu")
		(net "M_B_CPU1_SA_DQS_DP<8>")
	)
	(segment
		(start 60.090812 -278.82215)
		(end 58.263028 -279.579578)
		(width 0.18288)
		(layer "In4.Cu")
		(net "M_B_CPU1_SA_DQS_DP<8>")
	)
	(segment
		(start 74.947272 -265.68654)
		(end 74.55916 -266.074652)
		(width 0.18288)
		(layer "In4.Cu")
		(net "M_B_CPU1_SA_DQS_DP<8>")
	)
	(segment
		(start 82.879946 -262.52043)
		(end 82.820256 -262.46074)
		(width 0.088646)
		(layer "In4.Cu")
		(net "M_B_CPU1_SA_DQS_DP<8>")
	)
	(segment
		(start 83.556348 -262.433562)
		(end 83.300316 -262.433562)
		(width 0.088646)
		(layer "In4.Cu")
		(net "M_B_CPU1_SA_DQS_DP<8>")
	)
	(segment
		(start 51.36007 -283.437076)
		(end 51.089814 -283.16682)
		(width 0.18288)
		(layer "In4.Cu")
		(net "M_B_CPU1_SA_DQS_DP<8>")
	)
	(segment
		(start 69.7992 -270.834612)
		(end 69.7992 -271.010634)
		(width 0.18288)
		(layer "In4.Cu")
		(net "M_B_CPU1_SA_DQS_DP<8>")
	)
	(segment
		(start 91.832938 -262.386318)
		(end 91.821254 -262.379714)
		(width 0.088646)
		(layer "In4.Cu")
		(net "M_B_CPU1_SA_DQS_DP<8>")
	)
	(segment
		(start 52.653184 -283.481272)
		(end 52.38623 -283.591762)
		(width 0.18288)
		(layer "In4.Cu")
		(net "M_B_CPU1_SA_DQS_DP<8>")
	)
	(segment
		(start 68.847208 -271.962626)
		(end 67.785742 -273.024092)
		(width 0.18288)
		(layer "In4.Cu")
		(net "M_B_CPU1_SA_DQS_DP<8>")
	)
	(segment
		(start 73.043288 -267.590524)
		(end 72.655176 -267.978636)
		(width 0.18288)
		(layer "In4.Cu")
		(net "M_B_CPU1_SA_DQS_DP<8>")
	)
	(segment
		(start 73.21931 -267.590524)
		(end 73.043288 -267.590524)
		(width 0.18288)
		(layer "In4.Cu")
		(net "M_B_CPU1_SA_DQS_DP<8>")
	)
	(segment
		(start 63.634874 -274.743164)
		(end 63.33109 -275.046948)
		(width 0.18288)
		(layer "In4.Cu")
		(net "M_B_CPU1_SA_DQS_DP<8>")
	)
	(segment
		(start 89.951814 -262.385556)
		(end 89.947496 -262.383016)
		(width 0.088646)
		(layer "In4.Cu")
		(net "M_B_CPU1_SA_DQS_DP<8>")
	)
	(segment
		(start 93.423994 -262.872474)
		(end 93.419168 -262.867648)
		(width 0.088646)
		(layer "In4.Cu")
		(net "M_B_CPU1_SA_DQS_DP<8>")
	)
	(segment
		(start 51.998372 -283.591762)
		(end 51.843686 -283.437076)
		(width 0.18288)
		(layer "In4.Cu")
		(net "M_B_CPU1_SA_DQS_DP<8>")
	)
	(segment
		(start 70.187312 -270.4465)
		(end 69.7992 -270.834612)
		(width 0.18288)
		(layer "In4.Cu")
		(net "M_B_CPU1_SA_DQS_DP<8>")
	)
	(segment
		(start 69.411342 -271.398492)
		(end 69.23532 -271.398492)
		(width 0.18288)
		(layer "In4.Cu")
		(net "M_B_CPU1_SA_DQS_DP<8>")
	)
	(arc
		(start 92.761054 -262.379714)
		(mid 92.480949 -262.307272)
		(end 92.201746 -262.383016)
		(width 0.088646)
		(layer "In4.Cu")
		(net "M_B_CPU1_SA_DQS_DP<8>")
	)
	(arc
		(start 84.308696 -262.383016)
		(mid 84.025994 -262.30724)
		(end 83.743292 -262.383016)
		(width 0.088646)
		(layer "In4.Cu")
		(net "M_B_CPU1_SA_DQS_DP<8>")
	)
	(arc
		(start 84.683092 -262.383016)
		(mid 84.495894 -262.433159)
		(end 84.308696 -262.383016)
		(width 0.088646)
		(layer "In4.Cu")
		(net "M_B_CPU1_SA_DQS_DP<8>")
	)
	(arc
		(start 85.622892 -262.383016)
		(mid 85.435694 -262.433159)
		(end 85.248496 -262.383016)
		(width 0.088646)
		(layer "In4.Cu")
		(net "M_B_CPU1_SA_DQS_DP<8>")
	)
	(arc
		(start 91.261946 -262.383016)
		(mid 91.077992 -262.433145)
		(end 90.893138 -262.386318)
		(width 0.088646)
		(layer "In4.Cu")
		(net "M_B_CPU1_SA_DQS_DP<8>")
	)
	(arc
		(start 87.502492 -262.383016)
		(mid 87.315294 -262.433159)
		(end 87.128096 -262.383016)
		(width 0.088646)
		(layer "In4.Cu")
		(net "M_B_CPU1_SA_DQS_DP<8>")
	)
	(arc
		(start 86.562692 -262.383016)
		(mid 86.375494 -262.433159)
		(end 86.188296 -262.383016)
		(width 0.088646)
		(layer "In4.Cu")
		(net "M_B_CPU1_SA_DQS_DP<8>")
	)
	(arc
		(start 91.821254 -262.379714)
		(mid 91.541149 -262.307272)
		(end 91.261946 -262.383016)
		(width 0.088646)
		(layer "In4.Cu")
		(net "M_B_CPU1_SA_DQS_DP<8>")
	)
	(arc
		(start 86.188296 -262.383016)
		(mid 85.905594 -262.30724)
		(end 85.622892 -262.383016)
		(width 0.088646)
		(layer "In4.Cu")
		(net "M_B_CPU1_SA_DQS_DP<8>")
	)
	(arc
		(start 85.248496 -262.383016)
		(mid 84.965794 -262.30724)
		(end 84.683092 -262.383016)
		(width 0.088646)
		(layer "In4.Cu")
		(net "M_B_CPU1_SA_DQS_DP<8>")
	)
	(arc
		(start 93.419168 -262.867648)
		(mid 93.134747 -262.619563)
		(end 92.81922 -262.41248)
		(width 0.088646)
		(layer "In4.Cu")
		(net "M_B_CPU1_SA_DQS_DP<8>")
	)
	(arc
		(start 87.128096 -262.383016)
		(mid 86.845394 -262.30724)
		(end 86.562692 -262.383016)
		(width 0.088646)
		(layer "In4.Cu")
		(net "M_B_CPU1_SA_DQS_DP<8>")
	)
	(arc
		(start 90.322146 -262.383016)
		(mid 90.137309 -262.433277)
		(end 89.951814 -262.385556)
		(width 0.088646)
		(layer "In4.Cu")
		(net "M_B_CPU1_SA_DQS_DP<8>")
	)
	(arc
		(start 90.881454 -262.379714)
		(mid 90.601349 -262.307272)
		(end 90.322146 -262.383016)
		(width 0.088646)
		(layer "In4.Cu")
		(net "M_B_CPU1_SA_DQS_DP<8>")
	)
	(arc
		(start 89.00795 -262.383016)
		(mid 88.731137 -262.307146)
		(end 88.452706 -262.37692)
		(width 0.088646)
		(layer "In4.Cu")
		(net "M_B_CPU1_SA_DQS_DP<8>")
	)
	(arc
		(start 89.947496 -262.383016)
		(mid 89.664938 -262.307367)
		(end 89.382346 -262.383016)
		(width 0.088646)
		(layer "In4.Cu")
		(net "M_B_CPU1_SA_DQS_DP<8>")
	)
	(arc
		(start 88.067896 -262.383016)
		(mid 87.785194 -262.30724)
		(end 87.502492 -262.383016)
		(width 0.088646)
		(layer "In4.Cu")
		(net "M_B_CPU1_SA_DQS_DP<8>")
	)
	(arc
		(start 83.743038 -262.38327)
		(mid 83.652992 -262.420656)
		(end 83.556348 -262.433562)
		(width 0.088646)
		(layer "In4.Cu")
		(net "M_B_CPU1_SA_DQS_DP<8>")
	)
	(arc
		(start 88.442292 -262.383016)
		(mid 88.255094 -262.433159)
		(end 88.067896 -262.383016)
		(width 0.088646)
		(layer "In4.Cu")
		(net "M_B_CPU1_SA_DQS_DP<8>")
	)
	(arc
		(start 92.201746 -262.383016)
		(mid 92.017792 -262.433145)
		(end 91.832938 -262.386318)
		(width 0.088646)
		(layer "In4.Cu")
		(net "M_B_CPU1_SA_DQS_DP<8>")
	)
	(arc
		(start 89.382346 -262.383016)
		(mid 89.197225 -262.433279)
		(end 89.011506 -262.385302)
		(width 0.088646)
		(layer "In4.Cu")
		(net "M_B_CPU1_SA_DQS_DP<8>")
	)
	(segment
		(start 43.908218 -292.355524)
		(end 43.485816 -292.777926)
		(width 0.20066)
		(layer "F.Cu")
		(net "M_B_CPU1_SA_DQS_DP<7>")
	)
	(segment
		(start 49.208436 -292.777926)
		(end 48.603916 -292.777926)
		(width 0.20066)
		(layer "F.Cu")
		(net "M_B_CPU1_SA_DQS_DP<7>")
	)
	(segment
		(start 49.469548 -292.516814)
		(end 49.208436 -292.777926)
		(width 0.20066)
		(layer "F.Cu")
		(net "M_B_CPU1_SA_DQS_DP<7>")
	)
	(segment
		(start 44.735242 -292.08603)
		(end 44.537884 -292.08603)
		(width 0.20066)
		(layer "F.Cu")
		(net "M_B_CPU1_SA_DQS_DP<7>")
	)
	(segment
		(start 91.074494 -264.778236)
		(end 91.074494 -265.313922)
		(width 0.20066)
		(layer "F.Cu")
		(net "M_B_CPU1_SA_DQS_DP<7>")
	)
	(segment
		(start 44.537884 -292.08603)
		(end 44.26839 -292.355524)
		(width 0.20066)
		(layer "F.Cu")
		(net "M_B_CPU1_SA_DQS_DP<7>")
	)
	(segment
		(start 51.089814 -292.516814)
		(end 49.959514 -292.516814)
		(width 0.20066)
		(layer "F.Cu")
		(net "M_B_CPU1_SA_DQS_DP<7>")
	)
	(segment
		(start 44.741084 -292.091872)
		(end 44.735242 -292.08603)
		(width 0.101854)
		(layer "F.Cu")
		(net "M_B_CPU1_SA_DQS_DP<7>")
	)
	(segment
		(start 49.959514 -292.516814)
		(end 49.469548 -292.516814)
		(width 0.20066)
		(layer "F.Cu")
		(net "M_B_CPU1_SA_DQS_DP<7>")
	)
	(segment
		(start 91.074494 -265.313922)
		(end 91.074748 -265.314176)
		(width 0.20066)
		(layer "F.Cu")
		(net "M_B_CPU1_SA_DQS_DP<7>")
	)
	(segment
		(start 47.060358 -292.091872)
		(end 44.981876 -292.091872)
		(width 0.1016)
		(layer "F.Cu")
		(net "M_B_CPU1_SA_DQS_DP<7>")
	)
	(segment
		(start 43.151552 -292.777926)
		(end 42.89044 -292.516814)
		(width 0.20066)
		(layer "F.Cu")
		(net "M_B_CPU1_SA_DQS_DP<7>")
	)
	(segment
		(start 44.26839 -292.355524)
		(end 43.908218 -292.355524)
		(width 0.20066)
		(layer "F.Cu")
		(net "M_B_CPU1_SA_DQS_DP<7>")
	)
	(segment
		(start 47.201836 -292.091872)
		(end 47.060358 -292.091872)
		(width 0.20066)
		(layer "F.Cu")
		(net "M_B_CPU1_SA_DQS_DP<7>")
	)
	(segment
		(start 44.981876 -292.091872)
		(end 44.741084 -292.091872)
		(width 0.101854)
		(layer "F.Cu")
		(net "M_B_CPU1_SA_DQS_DP<7>")
	)
	(segment
		(start 47.9679 -292.352984)
		(end 47.462948 -292.352984)
		(width 0.20066)
		(layer "F.Cu")
		(net "M_B_CPU1_SA_DQS_DP<7>")
	)
	(segment
		(start 43.485816 -292.777926)
		(end 43.151552 -292.777926)
		(width 0.20066)
		(layer "F.Cu")
		(net "M_B_CPU1_SA_DQS_DP<7>")
	)
	(segment
		(start 48.603916 -292.777926)
		(end 47.9679 -292.352984)
		(width 0.20066)
		(layer "F.Cu")
		(net "M_B_CPU1_SA_DQS_DP<7>")
	)
	(segment
		(start 47.462948 -292.352984)
		(end 47.201836 -292.091872)
		(width 0.20066)
		(layer "F.Cu")
		(net "M_B_CPU1_SA_DQS_DP<7>")
	)
	(segment
		(start 42.89044 -292.516814)
		(end 42.415714 -292.516814)
		(width 0.20066)
		(layer "F.Cu")
		(net "M_B_CPU1_SA_DQS_DP<7>")
	)
	(segment
		(start 83.620864 -264.875518)
		(end 82.069432 -266.42695)
		(width 0.088646)
		(layer "In2.Cu")
		(net "M_B_CPU1_SA_DQS_DP<7>")
	)
	(segment
		(start 60.02147 -285.945326)
		(end 59.821318 -286.145478)
		(width 0.16002)
		(layer "In2.Cu")
		(net "M_B_CPU1_SA_DQS_DP<7>")
	)
	(segment
		(start 65.97523 -282.542742)
		(end 65.97523 -282.526994)
		(width 0.16002)
		(layer "In2.Cu")
		(net "M_B_CPU1_SA_DQS_DP<7>")
	)
	(segment
		(start 58.40222 -287.664906)
		(end 58.374026 -287.6931)
		(width 0.16002)
		(layer "In2.Cu")
		(net "M_B_CPU1_SA_DQS_DP<7>")
	)
	(segment
		(start 66.219324 -282.771088)
		(end 66.19113 -282.742894)
		(width 0.16002)
		(layer "In2.Cu")
		(net "M_B_CPU1_SA_DQS_DP<7>")
	)
	(segment
		(start 79.151988 -268.65961)
		(end 69.588126 -278.223472)
		(width 0.18288)
		(layer "In2.Cu")
		(net "M_B_CPU1_SA_DQS_DP<7>")
	)
	(segment
		(start 59.821318 -286.145478)
		(end 59.80557 -286.145478)
		(width 0.16002)
		(layer "In2.Cu")
		(net "M_B_CPU1_SA_DQS_DP<7>")
	)
	(segment
		(start 54.273958 -291.943028)
		(end 54.273958 -291.959284)
		(width 0.16002)
		(layer "In2.Cu")
		(net "M_B_CPU1_SA_DQS_DP<7>")
	)
	(segment
		(start 90.429588 -264.83183)
		(end 90.417396 -264.824718)
		(width 0.088646)
		(layer "In2.Cu")
		(net "M_B_CPU1_SA_DQS_DP<7>")
	)
	(segment
		(start 56.603392 -288.449004)
		(end 56.575198 -288.477198)
		(width 0.16002)
		(layer "In2.Cu")
		(net "M_B_CPU1_SA_DQS_DP<7>")
	)
	(segment
		(start 63.85306 -282.802076)
		(end 63.824866 -282.83027)
		(width 0.16002)
		(layer "In2.Cu")
		(net "M_B_CPU1_SA_DQS_DP<7>")
	)
	(segment
		(start 58.129932 -287.937194)
		(end 57.996836 -288.07029)
		(width 0.18288)
		(layer "In2.Cu")
		(net "M_B_CPU1_SA_DQS_DP<7>")
	)
	(segment
		(start 65.806066 -282.35783)
		(end 64.297306 -282.35783)
		(width 0.18288)
		(layer "In2.Cu")
		(net "M_B_CPU1_SA_DQS_DP<7>")
	)
	(segment
		(start 64.06896 -282.601924)
		(end 63.868808 -282.802076)
		(width 0.16002)
		(layer "In2.Cu")
		(net "M_B_CPU1_SA_DQS_DP<7>")
	)
	(segment
		(start 52.859686 -292.32479)
		(end 52.557426 -292.62705)
		(width 0.18288)
		(layer "In2.Cu")
		(net "M_B_CPU1_SA_DQS_DP<7>")
	)
	(segment
		(start 59.80557 -286.145478)
		(end 59.777376 -286.173672)
		(width 0.16002)
		(layer "In2.Cu")
		(net "M_B_CPU1_SA_DQS_DP<7>")
	)
	(segment
		(start 61.672216 -285.286958)
		(end 61.65596 -285.286958)
		(width 0.16002)
		(layer "In2.Cu")
		(net "M_B_CPU1_SA_DQS_DP<7>")
	)
	(segment
		(start 54.273958 -291.959284)
		(end 54.074314 -292.158928)
		(width 0.16002)
		(layer "In2.Cu")
		(net "M_B_CPU1_SA_DQS_DP<7>")
	)
	(segment
		(start 52.557426 -292.62705)
		(end 52.529232 -292.655244)
		(width 0.16002)
		(layer "In2.Cu")
		(net "M_B_CPU1_SA_DQS_DP<7>")
	)
	(segment
		(start 54.058058 -292.158928)
		(end 54.029864 -292.187122)
		(width 0.16002)
		(layer "In2.Cu")
		(net "M_B_CPU1_SA_DQS_DP<7>")
	)
	(segment
		(start 62.000638 -284.94228)
		(end 61.900054 -285.042864)
		(width 0.18288)
		(layer "In2.Cu")
		(net "M_B_CPU1_SA_DQS_DP<7>")
	)
	(segment
		(start 56.375046 -288.693098)
		(end 56.359298 -288.693098)
		(width 0.16002)
		(layer "In2.Cu")
		(net "M_B_CPU1_SA_DQS_DP<7>")
	)
	(segment
		(start 80.179672 -268.232382)
		(end 79.151988 -268.65961)
		(width 0.18288)
		(layer "In2.Cu")
		(net "M_B_CPU1_SA_DQS_DP<7>")
	)
	(segment
		(start 64.297306 -282.35783)
		(end 64.097154 -282.557982)
		(width 0.18288)
		(layer "In2.Cu")
		(net "M_B_CPU1_SA_DQS_DP<7>")
	)
	(segment
		(start 64.06896 -282.586176)
		(end 64.06896 -282.601924)
		(width 0.16002)
		(layer "In2.Cu")
		(net "M_B_CPU1_SA_DQS_DP<7>")
	)
	(segment
		(start 52.313332 -292.871144)
		(end 52.285138 -292.899338)
		(width 0.16002)
		(layer "In2.Cu")
		(net "M_B_CPU1_SA_DQS_DP<7>")
	)
	(segment
		(start 67.03187 -281.893518)
		(end 67.03187 -282.344876)
		(width 0.18288)
		(layer "In2.Cu")
		(net "M_B_CPU1_SA_DQS_DP<7>")
	)
	(segment
		(start 56.982106 -288.07029)
		(end 56.603392 -288.449004)
		(width 0.18288)
		(layer "In2.Cu")
		(net "M_B_CPU1_SA_DQS_DP<7>")
	)
	(segment
		(start 69.588126 -279.337262)
		(end 67.03187 -281.893518)
		(width 0.18288)
		(layer "In2.Cu")
		(net "M_B_CPU1_SA_DQS_DP<7>")
	)
	(segment
		(start 63.824866 -282.83027)
		(end 62.000638 -284.654498)
		(width 0.18288)
		(layer "In2.Cu")
		(net "M_B_CPU1_SA_DQS_DP<7>")
	)
	(segment
		(start 52.529232 -292.670992)
		(end 52.32908 -292.871144)
		(width 0.16002)
		(layer "In2.Cu")
		(net "M_B_CPU1_SA_DQS_DP<7>")
	)
	(segment
		(start 57.996836 -288.07029)
		(end 56.982106 -288.07029)
		(width 0.18288)
		(layer "In2.Cu")
		(net "M_B_CPU1_SA_DQS_DP<7>")
	)
	(segment
		(start 61.65596 -285.286958)
		(end 61.627766 -285.315152)
		(width 0.16002)
		(layer "In2.Cu")
		(net "M_B_CPU1_SA_DQS_DP<7>")
	)
	(segment
		(start 56.331104 -288.721292)
		(end 55.834026 -289.218116)
		(width 0.18288)
		(layer "In2.Cu")
		(net "M_B_CPU1_SA_DQS_DP<7>")
	)
	(segment
		(start 55.01005 -291.206936)
		(end 54.302152 -291.914834)
		(width 0.18288)
		(layer "In2.Cu")
		(net "M_B_CPU1_SA_DQS_DP<7>")
	)
	(segment
		(start 61.627766 -285.315152)
		(end 61.39434 -285.548578)
		(width 0.18288)
		(layer "In2.Cu")
		(net "M_B_CPU1_SA_DQS_DP<7>")
	)
	(segment
		(start 66.551048 -282.825698)
		(end 66.273934 -282.825698)
		(width 0.18288)
		(layer "In2.Cu")
		(net "M_B_CPU1_SA_DQS_DP<7>")
	)
	(segment
		(start 51.722528 -292.823138)
		(end 51.396138 -292.823138)
		(width 0.18288)
		(layer "In2.Cu")
		(net "M_B_CPU1_SA_DQS_DP<7>")
	)
	(segment
		(start 64.097154 -282.557982)
		(end 64.06896 -282.586176)
		(width 0.16002)
		(layer "In2.Cu")
		(net "M_B_CPU1_SA_DQS_DP<7>")
	)
	(segment
		(start 58.374026 -287.6931)
		(end 58.374026 -287.709356)
		(width 0.16002)
		(layer "In2.Cu")
		(net "M_B_CPU1_SA_DQS_DP<7>")
	)
	(segment
		(start 58.374026 -287.709356)
		(end 58.174382 -287.909)
		(width 0.16002)
		(layer "In2.Cu")
		(net "M_B_CPU1_SA_DQS_DP<7>")
	)
	(segment
		(start 84.025994 -264.875518)
		(end 83.620864 -264.875518)
		(width 0.088646)
		(layer "In2.Cu")
		(net "M_B_CPU1_SA_DQS_DP<7>")
	)
	(segment
		(start 58.858658 -287.09239)
		(end 58.858658 -287.208468)
		(width 0.18288)
		(layer "In2.Cu")
		(net "M_B_CPU1_SA_DQS_DP<7>")
	)
	(segment
		(start 66.273934 -282.825698)
		(end 66.219324 -282.771088)
		(width 0.18288)
		(layer "In2.Cu")
		(net "M_B_CPU1_SA_DQS_DP<7>")
	)
	(segment
		(start 66.19113 -282.742894)
		(end 66.175382 -282.742894)
		(width 0.16002)
		(layer "In2.Cu")
		(net "M_B_CPU1_SA_DQS_DP<7>")
	)
	(segment
		(start 51.89728 -292.99789)
		(end 51.722528 -292.823138)
		(width 0.18288)
		(layer "In2.Cu")
		(net "M_B_CPU1_SA_DQS_DP<7>")
	)
	(segment
		(start 63.868808 -282.802076)
		(end 63.85306 -282.802076)
		(width 0.16002)
		(layer "In2.Cu")
		(net "M_B_CPU1_SA_DQS_DP<7>")
	)
	(segment
		(start 61.87186 -285.087314)
		(end 61.672216 -285.286958)
		(width 0.16002)
		(layer "In2.Cu")
		(net "M_B_CPU1_SA_DQS_DP<7>")
	)
	(segment
		(start 56.575198 -288.477198)
		(end 56.575198 -288.492946)
		(width 0.16002)
		(layer "In2.Cu")
		(net "M_B_CPU1_SA_DQS_DP<7>")
	)
	(segment
		(start 56.575198 -288.492946)
		(end 56.375046 -288.693098)
		(width 0.16002)
		(layer "In2.Cu")
		(net "M_B_CPU1_SA_DQS_DP<7>")
	)
	(segment
		(start 59.777376 -286.173672)
		(end 58.858658 -287.09239)
		(width 0.18288)
		(layer "In2.Cu")
		(net "M_B_CPU1_SA_DQS_DP<7>")
	)
	(segment
		(start 60.049664 -285.901384)
		(end 60.02147 -285.929578)
		(width 0.16002)
		(layer "In2.Cu")
		(net "M_B_CPU1_SA_DQS_DP<7>")
	)
	(segment
		(start 69.588126 -278.223472)
		(end 69.588126 -279.337262)
		(width 0.18288)
		(layer "In2.Cu")
		(net "M_B_CPU1_SA_DQS_DP<7>")
	)
	(segment
		(start 91.074748 -265.314176)
		(end 90.762074 -265.314176)
		(width 0.088646)
		(layer "In2.Cu")
		(net "M_B_CPU1_SA_DQS_DP<7>")
	)
	(segment
		(start 58.158126 -287.909)
		(end 58.129932 -287.937194)
		(width 0.16002)
		(layer "In2.Cu")
		(net "M_B_CPU1_SA_DQS_DP<7>")
	)
	(segment
		(start 62.000638 -284.654498)
		(end 62.000638 -284.94228)
		(width 0.18288)
		(layer "In2.Cu")
		(net "M_B_CPU1_SA_DQS_DP<7>")
	)
	(segment
		(start 56.359298 -288.693098)
		(end 56.331104 -288.721292)
		(width 0.16002)
		(layer "In2.Cu")
		(net "M_B_CPU1_SA_DQS_DP<7>")
	)
	(segment
		(start 54.302152 -291.914834)
		(end 54.273958 -291.943028)
		(width 0.16002)
		(layer "In2.Cu")
		(net "M_B_CPU1_SA_DQS_DP<7>")
	)
	(segment
		(start 58.174382 -287.909)
		(end 58.158126 -287.909)
		(width 0.16002)
		(layer "In2.Cu")
		(net "M_B_CPU1_SA_DQS_DP<7>")
	)
	(segment
		(start 65.97523 -282.526994)
		(end 65.947036 -282.4988)
		(width 0.16002)
		(layer "In2.Cu")
		(net "M_B_CPU1_SA_DQS_DP<7>")
	)
	(segment
		(start 67.03187 -282.344876)
		(end 66.551048 -282.825698)
		(width 0.18288)
		(layer "In2.Cu")
		(net "M_B_CPU1_SA_DQS_DP<7>")
	)
	(segment
		(start 52.285138 -292.899338)
		(end 52.186586 -292.99789)
		(width 0.18288)
		(layer "In2.Cu")
		(net "M_B_CPU1_SA_DQS_DP<7>")
	)
	(segment
		(start 53.892196 -292.32479)
		(end 52.859686 -292.32479)
		(width 0.18288)
		(layer "In2.Cu")
		(net "M_B_CPU1_SA_DQS_DP<7>")
	)
	(segment
		(start 60.40247 -285.548578)
		(end 60.049664 -285.901384)
		(width 0.18288)
		(layer "In2.Cu")
		(net "M_B_CPU1_SA_DQS_DP<7>")
	)
	(segment
		(start 54.029864 -292.187122)
		(end 53.892196 -292.32479)
		(width 0.18288)
		(layer "In2.Cu")
		(net "M_B_CPU1_SA_DQS_DP<7>")
	)
	(segment
		(start 55.834026 -289.218116)
		(end 55.01005 -291.206936)
		(width 0.18288)
		(layer "In2.Cu")
		(net "M_B_CPU1_SA_DQS_DP<7>")
	)
	(segment
		(start 61.39434 -285.548578)
		(end 60.40247 -285.548578)
		(width 0.18288)
		(layer "In2.Cu")
		(net "M_B_CPU1_SA_DQS_DP<7>")
	)
	(segment
		(start 60.02147 -285.929578)
		(end 60.02147 -285.945326)
		(width 0.16002)
		(layer "In2.Cu")
		(net "M_B_CPU1_SA_DQS_DP<7>")
	)
	(segment
		(start 90.762074 -265.314176)
		(end 90.696288 -265.24839)
		(width 0.088646)
		(layer "In2.Cu")
		(net "M_B_CPU1_SA_DQS_DP<7>")
	)
	(segment
		(start 81.985104 -266.42695)
		(end 80.179672 -268.232382)
		(width 0.18288)
		(layer "In2.Cu")
		(net "M_B_CPU1_SA_DQS_DP<7>")
	)
	(segment
		(start 52.32908 -292.871144)
		(end 52.313332 -292.871144)
		(width 0.16002)
		(layer "In2.Cu")
		(net "M_B_CPU1_SA_DQS_DP<7>")
	)
	(segment
		(start 51.396138 -292.823138)
		(end 51.089814 -292.516814)
		(width 0.18288)
		(layer "In2.Cu")
		(net "M_B_CPU1_SA_DQS_DP<7>")
	)
	(segment
		(start 82.069432 -266.42695)
		(end 81.985104 -266.42695)
		(width 0.088646)
		(layer "In2.Cu")
		(net "M_B_CPU1_SA_DQS_DP<7>")
	)
	(segment
		(start 61.900054 -285.042864)
		(end 61.87186 -285.071058)
		(width 0.16002)
		(layer "In2.Cu")
		(net "M_B_CPU1_SA_DQS_DP<7>")
	)
	(segment
		(start 65.947036 -282.4988)
		(end 65.806066 -282.35783)
		(width 0.18288)
		(layer "In2.Cu")
		(net "M_B_CPU1_SA_DQS_DP<7>")
	)
	(segment
		(start 52.186586 -292.99789)
		(end 51.89728 -292.99789)
		(width 0.18288)
		(layer "In2.Cu")
		(net "M_B_CPU1_SA_DQS_DP<7>")
	)
	(segment
		(start 52.529232 -292.655244)
		(end 52.529232 -292.670992)
		(width 0.16002)
		(layer "In2.Cu")
		(net "M_B_CPU1_SA_DQS_DP<7>")
	)
	(segment
		(start 58.858658 -287.208468)
		(end 58.40222 -287.664906)
		(width 0.18288)
		(layer "In2.Cu")
		(net "M_B_CPU1_SA_DQS_DP<7>")
	)
	(segment
		(start 61.87186 -285.071058)
		(end 61.87186 -285.087314)
		(width 0.16002)
		(layer "In2.Cu")
		(net "M_B_CPU1_SA_DQS_DP<7>")
	)
	(segment
		(start 54.074314 -292.158928)
		(end 54.058058 -292.158928)
		(width 0.16002)
		(layer "In2.Cu")
		(net "M_B_CPU1_SA_DQS_DP<7>")
	)
	(segment
		(start 66.175382 -282.742894)
		(end 65.97523 -282.542742)
		(width 0.16002)
		(layer "In2.Cu")
		(net "M_B_CPU1_SA_DQS_DP<7>")
	)
	(arc
		(start 87.597996 -264.824718)
		(mid 87.315294 -264.748942)
		(end 87.032592 -264.824718)
		(width 0.088646)
		(layer "In2.Cu")
		(net "M_B_CPU1_SA_DQS_DP<7>")
	)
	(arc
		(start 84.778596 -264.824718)
		(mid 84.495894 -264.748942)
		(end 84.213192 -264.824718)
		(width 0.088646)
		(layer "In2.Cu")
		(net "M_B_CPU1_SA_DQS_DP<7>")
	)
	(arc
		(start 86.658196 -264.824718)
		(mid 86.375494 -264.748942)
		(end 86.092792 -264.824718)
		(width 0.088646)
		(layer "In2.Cu")
		(net "M_B_CPU1_SA_DQS_DP<7>")
	)
	(arc
		(start 90.417396 -264.824718)
		(mid 90.134694 -264.748942)
		(end 89.851992 -264.824718)
		(width 0.088646)
		(layer "In2.Cu")
		(net "M_B_CPU1_SA_DQS_DP<7>")
	)
	(arc
		(start 86.092792 -264.824718)
		(mid 85.905594 -264.874861)
		(end 85.718396 -264.824718)
		(width 0.088646)
		(layer "In2.Cu")
		(net "M_B_CPU1_SA_DQS_DP<7>")
	)
	(arc
		(start 87.972392 -264.824718)
		(mid 87.785194 -264.874861)
		(end 87.597996 -264.824718)
		(width 0.088646)
		(layer "In2.Cu")
		(net "M_B_CPU1_SA_DQS_DP<7>")
	)
	(arc
		(start 89.477596 -264.824718)
		(mid 89.194894 -264.748942)
		(end 88.912192 -264.824718)
		(width 0.088646)
		(layer "In2.Cu")
		(net "M_B_CPU1_SA_DQS_DP<7>")
	)
	(arc
		(start 87.032592 -264.824718)
		(mid 86.845394 -264.874861)
		(end 86.658196 -264.824718)
		(width 0.088646)
		(layer "In2.Cu")
		(net "M_B_CPU1_SA_DQS_DP<7>")
	)
	(arc
		(start 88.537796 -264.824718)
		(mid 88.255094 -264.748942)
		(end 87.972392 -264.824718)
		(width 0.088646)
		(layer "In2.Cu")
		(net "M_B_CPU1_SA_DQS_DP<7>")
	)
	(arc
		(start 89.851992 -264.824718)
		(mid 89.664794 -264.874861)
		(end 89.477596 -264.824718)
		(width 0.088646)
		(layer "In2.Cu")
		(net "M_B_CPU1_SA_DQS_DP<7>")
	)
	(arc
		(start 84.057998 -264.873994)
		(mid 84.042012 -264.875096)
		(end 84.025994 -264.875518)
		(width 0.088646)
		(layer "In2.Cu")
		(net "M_B_CPU1_SA_DQS_DP<7>")
	)
	(arc
		(start 85.152992 -264.824718)
		(mid 84.965794 -264.874861)
		(end 84.778596 -264.824718)
		(width 0.088646)
		(layer "In2.Cu")
		(net "M_B_CPU1_SA_DQS_DP<7>")
	)
	(arc
		(start 85.718396 -264.824718)
		(mid 85.435694 -264.748942)
		(end 85.152992 -264.824718)
		(width 0.088646)
		(layer "In2.Cu")
		(net "M_B_CPU1_SA_DQS_DP<7>")
	)
	(arc
		(start 84.213192 -264.824718)
		(mid 84.138299 -264.857862)
		(end 84.057998 -264.873994)
		(width 0.088646)
		(layer "In2.Cu")
		(net "M_B_CPU1_SA_DQS_DP<7>")
	)
	(arc
		(start 88.912192 -264.824718)
		(mid 88.724994 -264.874861)
		(end 88.537796 -264.824718)
		(width 0.088646)
		(layer "In2.Cu")
		(net "M_B_CPU1_SA_DQS_DP<7>")
	)
	(arc
		(start 90.696288 -265.24839)
		(mid 90.694987 -265.237963)
		(end 90.693494 -265.227562)
		(width 0.088646)
		(layer "In2.Cu")
		(net "M_B_CPU1_SA_DQS_DP<7>")
	)
	(arc
		(start 90.693494 -265.227562)
		(mid 90.605223 -265.000549)
		(end 90.429588 -264.83183)
		(width 0.088646)
		(layer "In2.Cu")
		(net "M_B_CPU1_SA_DQS_DP<7>")
	)
	(segment
		(start 47.201836 -301.441866)
		(end 47.060358 -301.441866)
		(width 0.20066)
		(layer "F.Cu")
		(net "M_B_CPU1_SA_DQS_DP<6>")
	)
	(segment
		(start 43.908218 -301.705518)
		(end 43.485816 -302.12792)
		(width 0.20066)
		(layer "F.Cu")
		(net "M_B_CPU1_SA_DQS_DP<6>")
	)
	(segment
		(start 49.469548 -301.866808)
		(end 49.208436 -302.12792)
		(width 0.20066)
		(layer "F.Cu")
		(net "M_B_CPU1_SA_DQS_DP<6>")
	)
	(segment
		(start 49.208436 -302.12792)
		(end 48.603916 -302.12792)
		(width 0.20066)
		(layer "F.Cu")
		(net "M_B_CPU1_SA_DQS_DP<6>")
	)
	(segment
		(start 44.26839 -301.705518)
		(end 43.908218 -301.705518)
		(width 0.20066)
		(layer "F.Cu")
		(net "M_B_CPU1_SA_DQS_DP<6>")
	)
	(segment
		(start 47.462948 -301.702978)
		(end 47.201836 -301.441866)
		(width 0.20066)
		(layer "F.Cu")
		(net "M_B_CPU1_SA_DQS_DP<6>")
	)
	(segment
		(start 51.089814 -301.866808)
		(end 49.959514 -301.866808)
		(width 0.20066)
		(layer "F.Cu")
		(net "M_B_CPU1_SA_DQS_DP<6>")
	)
	(segment
		(start 43.485816 -302.12792)
		(end 43.151552 -302.12792)
		(width 0.20066)
		(layer "F.Cu")
		(net "M_B_CPU1_SA_DQS_DP<6>")
	)
	(segment
		(start 44.735242 -301.436024)
		(end 44.537884 -301.436024)
		(width 0.20066)
		(layer "F.Cu")
		(net "M_B_CPU1_SA_DQS_DP<6>")
	)
	(segment
		(start 44.741084 -301.441866)
		(end 44.735242 -301.436024)
		(width 0.101854)
		(layer "F.Cu")
		(net "M_B_CPU1_SA_DQS_DP<6>")
	)
	(segment
		(start 44.537884 -301.436024)
		(end 44.26839 -301.705518)
		(width 0.20066)
		(layer "F.Cu")
		(net "M_B_CPU1_SA_DQS_DP<6>")
	)
	(segment
		(start 93.424248 -272.639028)
		(end 93.423994 -272.639282)
		(width 0.20066)
		(layer "F.Cu")
		(net "M_B_CPU1_SA_DQS_DP<6>")
	)
	(segment
		(start 47.060358 -301.441866)
		(end 44.981876 -301.441866)
		(width 0.1016)
		(layer "F.Cu")
		(net "M_B_CPU1_SA_DQS_DP<6>")
	)
	(segment
		(start 48.603916 -302.12792)
		(end 47.9679 -301.702978)
		(width 0.20066)
		(layer "F.Cu")
		(net "M_B_CPU1_SA_DQS_DP<6>")
	)
	(segment
		(start 47.9679 -301.702978)
		(end 47.462948 -301.702978)
		(width 0.20066)
		(layer "F.Cu")
		(net "M_B_CPU1_SA_DQS_DP<6>")
	)
	(segment
		(start 49.959514 -301.866808)
		(end 49.469548 -301.866808)
		(width 0.20066)
		(layer "F.Cu")
		(net "M_B_CPU1_SA_DQS_DP<6>")
	)
	(segment
		(start 44.981876 -301.441866)
		(end 44.741084 -301.441866)
		(width 0.101854)
		(layer "F.Cu")
		(net "M_B_CPU1_SA_DQS_DP<6>")
	)
	(segment
		(start 43.151552 -302.12792)
		(end 42.89044 -301.866808)
		(width 0.20066)
		(layer "F.Cu")
		(net "M_B_CPU1_SA_DQS_DP<6>")
	)
	(segment
		(start 42.89044 -301.866808)
		(end 42.415714 -301.866808)
		(width 0.20066)
		(layer "F.Cu")
		(net "M_B_CPU1_SA_DQS_DP<6>")
	)
	(segment
		(start 93.424248 -272.103342)
		(end 93.424248 -272.639028)
		(width 0.20066)
		(layer "F.Cu")
		(net "M_B_CPU1_SA_DQS_DP<6>")
	)
	(segment
		(start 82.266028 -277.124414)
		(end 81.878424 -277.513034)
		(width 0.18288)
		(layer "In4.Cu")
		(net "M_B_CPU1_SA_DQS_DP<6>")
	)
	(segment
		(start 74.3331 -287.63595)
		(end 74.123042 -288.143188)
		(width 0.18288)
		(layer "In4.Cu")
		(net "M_B_CPU1_SA_DQS_DP<6>")
	)
	(segment
		(start 81.878678 -277.689056)
		(end 81.491328 -278.077422)
		(width 0.18288)
		(layer "In4.Cu")
		(net "M_B_CPU1_SA_DQS_DP<6>")
	)
	(segment
		(start 85.149436 -274.593304)
		(end 85.146896 -274.594828)
		(width 0.088646)
		(layer "In4.Cu")
		(net "M_B_CPU1_SA_DQS_DP<6>")
	)
	(segment
		(start 85.632036 -273.772376)
		(end 85.62467 -273.776694)
		(width 0.088646)
		(layer "In4.Cu")
		(net "M_B_CPU1_SA_DQS_DP<6>")
	)
	(segment
		(start 80.927702 -278.466296)
		(end 80.927956 -278.642318)
		(width 0.18288)
		(layer "In4.Cu")
		(net "M_B_CPU1_SA_DQS_DP<6>")
	)
	(segment
		(start 52.050696 -302.342296)
		(end 51.840638 -302.132238)
		(width 0.18288)
		(layer "In4.Cu")
		(net "M_B_CPU1_SA_DQS_DP<6>")
	)
	(segment
		(start 75.66914 -284.411674)
		(end 75.73645 -284.574234)
		(width 0.18288)
		(layer "In4.Cu")
		(net "M_B_CPU1_SA_DQS_DP<6>")
	)
	(segment
		(start 75.153774 -285.655512)
		(end 75.221084 -285.818072)
		(width 0.18288)
		(layer "In4.Cu")
		(net "M_B_CPU1_SA_DQS_DP<6>")
	)
	(segment
		(start 58.076846 -300.194218)
		(end 56.420766 -301.850298)
		(width 0.18288)
		(layer "In4.Cu")
		(net "M_B_CPU1_SA_DQS_DP<6>")
	)
	(segment
		(start 73.674986 -289.549586)
		(end 72.516746 -292.346634)
		(width 0.18288)
		(layer "In4.Cu")
		(net "M_B_CPU1_SA_DQS_DP<6>")
	)
	(segment
		(start 59.841384 -298.97578)
		(end 58.6232 -300.194218)
		(width 0.18288)
		(layer "In4.Cu")
		(net "M_B_CPU1_SA_DQS_DP<6>")
	)
	(segment
		(start 73.817734 -288.879788)
		(end 73.607676 -289.387026)
		(width 0.18288)
		(layer "In4.Cu")
		(net "M_B_CPU1_SA_DQS_DP<6>")
	)
	(segment
		(start 75.526646 -285.080964)
		(end 75.363832 -285.148274)
		(width 0.18288)
		(layer "In4.Cu")
		(net "M_B_CPU1_SA_DQS_DP<6>")
	)
	(segment
		(start 92.84462 -272.194274)
		(end 92.76715 -272.14957)
		(width 0.088646)
		(layer "In4.Cu")
		(net "M_B_CPU1_SA_DQS_DP<6>")
	)
	(segment
		(start 60.854336 -298.306744)
		(end 60.428124 -298.732702)
		(width 0.18288)
		(layer "In4.Cu")
		(net "M_B_CPU1_SA_DQS_DP<6>")
	)
	(segment
		(start 85.810344 -273.453098)
		(end 85.810598 -273.453098)
		(width 0.088646)
		(layer "In4.Cu")
		(net "M_B_CPU1_SA_DQS_DP<6>")
	)
	(segment
		(start 85.152992 -274.591272)
		(end 85.15223 -274.59178)
		(width 0.088646)
		(layer "In4.Cu")
		(net "M_B_CPU1_SA_DQS_DP<6>")
	)
	(segment
		(start 54.674008 -302.342296)
		(end 52.050696 -302.342296)
		(width 0.18288)
		(layer "In4.Cu")
		(net "M_B_CPU1_SA_DQS_DP<6>")
	)
	(segment
		(start 83.884516 -276.129496)
		(end 83.824826 -276.069806)
		(width 0.088646)
		(layer "In4.Cu")
		(net "M_B_CPU1_SA_DQS_DP<6>")
	)
	(segment
		(start 62.246002 -298.042076)
		(end 61.855096 -298.042076)
		(width 0.18288)
		(layer "In4.Cu")
		(net "M_B_CPU1_SA_DQS_DP<6>")
	)
	(segment
		(start 77.12456 -282.279344)
		(end 77.124814 -282.455366)
		(width 0.18288)
		(layer "In4.Cu")
		(net "M_B_CPU1_SA_DQS_DP<6>")
	)
	(segment
		(start 78.075536 -281.326082)
		(end 78.075536 -281.502104)
		(width 0.18288)
		(layer "In4.Cu")
		(net "M_B_CPU1_SA_DQS_DP<6>")
	)
	(segment
		(start 75.73645 -284.574234)
		(end 75.526646 -285.080964)
		(width 0.18288)
		(layer "In4.Cu")
		(net "M_B_CPU1_SA_DQS_DP<6>")
	)
	(segment
		(start 75.01128 -286.324802)
		(end 74.848466 -286.392112)
		(width 0.18288)
		(layer "In4.Cu")
		(net "M_B_CPU1_SA_DQS_DP<6>")
	)
	(segment
		(start 76.042012 -283.837126)
		(end 75.879198 -283.904436)
		(width 0.18288)
		(layer "In4.Cu")
		(net "M_B_CPU1_SA_DQS_DP<6>")
	)
	(segment
		(start 79.413862 -279.9842)
		(end 79.026258 -280.37282)
		(width 0.18288)
		(layer "In4.Cu")
		(net "M_B_CPU1_SA_DQS_DP<6>")
	)
	(segment
		(start 61.590428 -298.306744)
		(end 60.854336 -298.306744)
		(width 0.18288)
		(layer "In4.Cu")
		(net "M_B_CPU1_SA_DQS_DP<6>")
	)
	(segment
		(start 83.824826 -276.069806)
		(end 83.801458 -276.069806)
		(width 0.088646)
		(layer "In4.Cu")
		(net "M_B_CPU1_SA_DQS_DP<6>")
	)
	(segment
		(start 76.251816 -283.330396)
		(end 76.042012 -283.837126)
		(width 0.18288)
		(layer "In4.Cu")
		(net "M_B_CPU1_SA_DQS_DP<6>")
	)
	(segment
		(start 75.363832 -285.148274)
		(end 75.153774 -285.655512)
		(width 0.18288)
		(layer "In4.Cu")
		(net "M_B_CPU1_SA_DQS_DP<6>")
	)
	(segment
		(start 55.861204 -301.850298)
		(end 54.674008 -302.342296)
		(width 0.18288)
		(layer "In4.Cu")
		(net "M_B_CPU1_SA_DQS_DP<6>")
	)
	(segment
		(start 74.495914 -287.56864)
		(end 74.3331 -287.63595)
		(width 0.18288)
		(layer "In4.Cu")
		(net "M_B_CPU1_SA_DQS_DP<6>")
	)
	(segment
		(start 84.87029 -275.09216)
		(end 84.8487 -275.306282)
		(width 0.088646)
		(layer "In4.Cu")
		(net "M_B_CPU1_SA_DQS_DP<6>")
	)
	(segment
		(start 81.491328 -278.077422)
		(end 81.315306 -278.077676)
		(width 0.18288)
		(layer "In4.Cu")
		(net "M_B_CPU1_SA_DQS_DP<6>")
	)
	(segment
		(start 77.512164 -281.890724)
		(end 77.12456 -282.279344)
		(width 0.18288)
		(layer "In4.Cu")
		(net "M_B_CPU1_SA_DQS_DP<6>")
	)
	(segment
		(start 65.54343 -296.8625)
		(end 64.093598 -298.312332)
		(width 0.18288)
		(layer "In4.Cu")
		(net "M_B_CPU1_SA_DQS_DP<6>")
	)
	(segment
		(start 73.607676 -289.387026)
		(end 73.674986 -289.549586)
		(width 0.18288)
		(layer "In4.Cu")
		(net "M_B_CPU1_SA_DQS_DP<6>")
	)
	(segment
		(start 74.123042 -288.143188)
		(end 74.190352 -288.305748)
		(width 0.18288)
		(layer "In4.Cu")
		(net "M_B_CPU1_SA_DQS_DP<6>")
	)
	(segment
		(start 80.364584 -279.030938)
		(end 79.97698 -279.419558)
		(width 0.18288)
		(layer "In4.Cu")
		(net "M_B_CPU1_SA_DQS_DP<6>")
	)
	(segment
		(start 75.879198 -283.904436)
		(end 75.66914 -284.411674)
		(width 0.18288)
		(layer "In4.Cu")
		(net "M_B_CPU1_SA_DQS_DP<6>")
	)
	(segment
		(start 74.848466 -286.392112)
		(end 74.638408 -286.89935)
		(width 0.18288)
		(layer "In4.Cu")
		(net "M_B_CPU1_SA_DQS_DP<6>")
	)
	(segment
		(start 83.801458 -276.069806)
		(end 83.495896 -276.069806)
		(width 0.18288)
		(layer "In4.Cu")
		(net "M_B_CPU1_SA_DQS_DP<6>")
	)
	(segment
		(start 91.272106 -272.143474)
		(end 91.261692 -272.14957)
		(width 0.088646)
		(layer "In4.Cu")
		(net "M_B_CPU1_SA_DQS_DP<6>")
	)
	(segment
		(start 56.420766 -301.850298)
		(end 55.861204 -301.850298)
		(width 0.18288)
		(layer "In4.Cu")
		(net "M_B_CPU1_SA_DQS_DP<6>")
	)
	(segment
		(start 77.688186 -281.89047)
		(end 77.512164 -281.890724)
		(width 0.18288)
		(layer "In4.Cu")
		(net "M_B_CPU1_SA_DQS_DP<6>")
	)
	(segment
		(start 89.39276 -272.143474)
		(end 89.382346 -272.14957)
		(width 0.088646)
		(layer "In4.Cu")
		(net "M_B_CPU1_SA_DQS_DP<6>")
	)
	(segment
		(start 84.8487 -275.306282)
		(end 84.025486 -276.129496)
		(width 0.088646)
		(layer "In4.Cu")
		(net "M_B_CPU1_SA_DQS_DP<6>")
	)
	(segment
		(start 85.154516 -274.59051)
		(end 85.152992 -274.591272)
		(width 0.088646)
		(layer "In4.Cu")
		(net "M_B_CPU1_SA_DQS_DP<6>")
	)
	(segment
		(start 75.221084 -285.818072)
		(end 75.01128 -286.324802)
		(width 0.18288)
		(layer "In4.Cu")
		(net "M_B_CPU1_SA_DQS_DP<6>")
	)
	(segment
		(start 84.87029 -275.08073)
		(end 84.87029 -275.09216)
		(width 0.088646)
		(layer "In4.Cu")
		(net "M_B_CPU1_SA_DQS_DP<6>")
	)
	(segment
		(start 81.315306 -278.077676)
		(end 80.927702 -278.466296)
		(width 0.18288)
		(layer "In4.Cu")
		(net "M_B_CPU1_SA_DQS_DP<6>")
	)
	(segment
		(start 89.00795 -272.14957)
		(end 88.997536 -272.143474)
		(width 0.088646)
		(layer "In4.Cu")
		(net "M_B_CPU1_SA_DQS_DP<6>")
	)
	(segment
		(start 78.075536 -281.502104)
		(end 77.688186 -281.89047)
		(width 0.18288)
		(layer "In4.Cu")
		(net "M_B_CPU1_SA_DQS_DP<6>")
	)
	(segment
		(start 74.190352 -288.305748)
		(end 73.980548 -288.812478)
		(width 0.18288)
		(layer "In4.Cu")
		(net "M_B_CPU1_SA_DQS_DP<6>")
	)
	(segment
		(start 51.355244 -302.132238)
		(end 51.089814 -301.866808)
		(width 0.18288)
		(layer "In4.Cu")
		(net "M_B_CPU1_SA_DQS_DP<6>")
	)
	(segment
		(start 92.216478 -272.140934)
		(end 92.201746 -272.14957)
		(width 0.088646)
		(layer "In4.Cu")
		(net "M_B_CPU1_SA_DQS_DP<6>")
	)
	(segment
		(start 80.927956 -278.642318)
		(end 80.540606 -279.030684)
		(width 0.18288)
		(layer "In4.Cu")
		(net "M_B_CPU1_SA_DQS_DP<6>")
	)
	(segment
		(start 51.840638 -302.132238)
		(end 51.355244 -302.132238)
		(width 0.18288)
		(layer "In4.Cu")
		(net "M_B_CPU1_SA_DQS_DP<6>")
	)
	(segment
		(start 78.639162 -280.937208)
		(end 78.46314 -280.937462)
		(width 0.18288)
		(layer "In4.Cu")
		(net "M_B_CPU1_SA_DQS_DP<6>")
	)
	(segment
		(start 81.878424 -277.513034)
		(end 81.878678 -277.689056)
		(width 0.18288)
		(layer "In4.Cu")
		(net "M_B_CPU1_SA_DQS_DP<6>")
	)
	(segment
		(start 83.495896 -276.069806)
		(end 82.44205 -277.12416)
		(width 0.18288)
		(layer "In4.Cu")
		(net "M_B_CPU1_SA_DQS_DP<6>")
	)
	(segment
		(start 74.638408 -286.89935)
		(end 74.705718 -287.06191)
		(width 0.18288)
		(layer "In4.Cu")
		(net "M_B_CPU1_SA_DQS_DP<6>")
	)
	(segment
		(start 85.62467 -273.776694)
		(end 85.623146 -273.777456)
		(width 0.088646)
		(layer "In4.Cu")
		(net "M_B_CPU1_SA_DQS_DP<6>")
	)
	(segment
		(start 74.705718 -287.06191)
		(end 74.495914 -287.56864)
		(width 0.18288)
		(layer "In4.Cu")
		(net "M_B_CPU1_SA_DQS_DP<6>")
	)
	(segment
		(start 79.97698 -279.419558)
		(end 79.977234 -279.59558)
		(width 0.18288)
		(layer "In4.Cu")
		(net "M_B_CPU1_SA_DQS_DP<6>")
	)
	(segment
		(start 82.44205 -277.12416)
		(end 82.266028 -277.124414)
		(width 0.18288)
		(layer "In4.Cu")
		(net "M_B_CPU1_SA_DQS_DP<6>")
	)
	(segment
		(start 73.980548 -288.812478)
		(end 73.817734 -288.879788)
		(width 0.18288)
		(layer "In4.Cu")
		(net "M_B_CPU1_SA_DQS_DP<6>")
	)
	(segment
		(start 61.855096 -298.042076)
		(end 61.590428 -298.306744)
		(width 0.18288)
		(layer "In4.Cu")
		(net "M_B_CPU1_SA_DQS_DP<6>")
	)
	(segment
		(start 84.025486 -276.129496)
		(end 83.884516 -276.129496)
		(width 0.088646)
		(layer "In4.Cu")
		(net "M_B_CPU1_SA_DQS_DP<6>")
	)
	(segment
		(start 68.00088 -296.8625)
		(end 65.54343 -296.8625)
		(width 0.18288)
		(layer "In4.Cu")
		(net "M_B_CPU1_SA_DQS_DP<6>")
	)
	(segment
		(start 79.589884 -279.983946)
		(end 79.413862 -279.9842)
		(width 0.18288)
		(layer "In4.Cu")
		(net "M_B_CPU1_SA_DQS_DP<6>")
	)
	(segment
		(start 60.428124 -298.732702)
		(end 59.841384 -298.97578)
		(width 0.18288)
		(layer "In4.Cu")
		(net "M_B_CPU1_SA_DQS_DP<6>")
	)
	(segment
		(start 79.026512 -280.548842)
		(end 78.639162 -280.937208)
		(width 0.18288)
		(layer "In4.Cu")
		(net "M_B_CPU1_SA_DQS_DP<6>")
	)
	(segment
		(start 72.516746 -292.346634)
		(end 68.00088 -296.8625)
		(width 0.18288)
		(layer "In4.Cu")
		(net "M_B_CPU1_SA_DQS_DP<6>")
	)
	(segment
		(start 86.280244 -272.625058)
		(end 86.280244 -272.639282)
		(width 0.088646)
		(layer "In4.Cu")
		(net "M_B_CPU1_SA_DQS_DP<6>")
	)
	(segment
		(start 86.092792 -272.96364)
		(end 86.086696 -272.967196)
		(width 0.088646)
		(layer "In4.Cu")
		(net "M_B_CPU1_SA_DQS_DP<6>")
	)
	(segment
		(start 79.977234 -279.59558)
		(end 79.589884 -279.983946)
		(width 0.18288)
		(layer "In4.Cu")
		(net "M_B_CPU1_SA_DQS_DP<6>")
	)
	(segment
		(start 85.623146 -273.777456)
		(end 85.622384 -273.777964)
		(width 0.088646)
		(layer "In4.Cu")
		(net "M_B_CPU1_SA_DQS_DP<6>")
	)
	(segment
		(start 85.161882 -274.586192)
		(end 85.154516 -274.59051)
		(width 0.088646)
		(layer "In4.Cu")
		(net "M_B_CPU1_SA_DQS_DP<6>")
	)
	(segment
		(start 58.6232 -300.194218)
		(end 58.076846 -300.194218)
		(width 0.18288)
		(layer "In4.Cu")
		(net "M_B_CPU1_SA_DQS_DP<6>")
	)
	(segment
		(start 80.540606 -279.030684)
		(end 80.364584 -279.030938)
		(width 0.18288)
		(layer "In4.Cu")
		(net "M_B_CPU1_SA_DQS_DP<6>")
	)
	(segment
		(start 90.887296 -272.14957)
		(end 90.872564 -272.140934)
		(width 0.088646)
		(layer "In4.Cu")
		(net "M_B_CPU1_SA_DQS_DP<6>")
	)
	(segment
		(start 85.151214 -274.592288)
		(end 85.149436 -274.593304)
		(width 0.088646)
		(layer "In4.Cu")
		(net "M_B_CPU1_SA_DQS_DP<6>")
	)
	(segment
		(start 85.622384 -273.777964)
		(end 85.61705 -273.781012)
		(width 0.088646)
		(layer "In4.Cu")
		(net "M_B_CPU1_SA_DQS_DP<6>")
	)
	(segment
		(start 85.15223 -274.59178)
		(end 85.151214 -274.592288)
		(width 0.088646)
		(layer "In4.Cu")
		(net "M_B_CPU1_SA_DQS_DP<6>")
	)
	(segment
		(start 64.093598 -298.312332)
		(end 62.516258 -298.312332)
		(width 0.18288)
		(layer "In4.Cu")
		(net "M_B_CPU1_SA_DQS_DP<6>")
	)
	(segment
		(start 87.128096 -272.14957)
		(end 87.113364 -272.140934)
		(width 0.088646)
		(layer "In4.Cu")
		(net "M_B_CPU1_SA_DQS_DP<6>")
	)
	(segment
		(start 86.101682 -272.95856)
		(end 86.092792 -272.96364)
		(width 0.088646)
		(layer "In4.Cu")
		(net "M_B_CPU1_SA_DQS_DP<6>")
	)
	(segment
		(start 77.124814 -282.455366)
		(end 76.251816 -283.330396)
		(width 0.18288)
		(layer "In4.Cu")
		(net "M_B_CPU1_SA_DQS_DP<6>")
	)
	(segment
		(start 78.46314 -280.937462)
		(end 78.075536 -281.326082)
		(width 0.18288)
		(layer "In4.Cu")
		(net "M_B_CPU1_SA_DQS_DP<6>")
	)
	(segment
		(start 62.516258 -298.312332)
		(end 62.246002 -298.042076)
		(width 0.18288)
		(layer "In4.Cu")
		(net "M_B_CPU1_SA_DQS_DP<6>")
	)
	(segment
		(start 79.026258 -280.37282)
		(end 79.026512 -280.548842)
		(width 0.18288)
		(layer "In4.Cu")
		(net "M_B_CPU1_SA_DQS_DP<6>")
	)
	(arc
		(start 93.423994 -272.639282)
		(mid 93.148853 -272.39784)
		(end 92.84462 -272.194274)
		(width 0.088646)
		(layer "In4.Cu")
		(net "M_B_CPU1_SA_DQS_DP<6>")
	)
	(arc
		(start 85.340444 -274.266914)
		(mid 85.292765 -274.449814)
		(end 85.161882 -274.586192)
		(width 0.088646)
		(layer "In4.Cu")
		(net "M_B_CPU1_SA_DQS_DP<6>")
	)
	(arc
		(start 88.442292 -272.14957)
		(mid 88.255094 -272.199713)
		(end 88.067896 -272.14957)
		(width 0.088646)
		(layer "In4.Cu")
		(net "M_B_CPU1_SA_DQS_DP<6>")
	)
	(arc
		(start 86.086696 -272.967196)
		(mid 85.884283 -273.173609)
		(end 85.810344 -273.453098)
		(width 0.088646)
		(layer "In4.Cu")
		(net "M_B_CPU1_SA_DQS_DP<6>")
	)
	(arc
		(start 88.067896 -272.14957)
		(mid 87.785194 -272.073828)
		(end 87.502492 -272.14957)
		(width 0.088646)
		(layer "In4.Cu")
		(net "M_B_CPU1_SA_DQS_DP<6>")
	)
	(arc
		(start 91.261692 -272.14957)
		(mid 91.074494 -272.199713)
		(end 90.887296 -272.14957)
		(width 0.088646)
		(layer "In4.Cu")
		(net "M_B_CPU1_SA_DQS_DP<6>")
	)
	(arc
		(start 85.146896 -274.594828)
		(mid 84.944309 -274.801179)
		(end 84.87029 -275.08073)
		(width 0.088646)
		(layer "In4.Cu")
		(net "M_B_CPU1_SA_DQS_DP<6>")
	)
	(arc
		(start 91.82735 -272.14957)
		(mid 91.550537 -272.073734)
		(end 91.272106 -272.143474)
		(width 0.088646)
		(layer "In4.Cu")
		(net "M_B_CPU1_SA_DQS_DP<6>")
	)
	(arc
		(start 85.810598 -273.453098)
		(mid 85.762919 -273.635998)
		(end 85.632036 -273.772376)
		(width 0.088646)
		(layer "In4.Cu")
		(net "M_B_CPU1_SA_DQS_DP<6>")
	)
	(arc
		(start 90.872564 -272.140934)
		(mid 90.596123 -272.073768)
		(end 90.321892 -272.14957)
		(width 0.088646)
		(layer "In4.Cu")
		(net "M_B_CPU1_SA_DQS_DP<6>")
	)
	(arc
		(start 92.201746 -272.14957)
		(mid 92.014548 -272.199713)
		(end 91.82735 -272.14957)
		(width 0.088646)
		(layer "In4.Cu")
		(net "M_B_CPU1_SA_DQS_DP<6>")
	)
	(arc
		(start 86.562692 -272.14957)
		(mid 86.359387 -272.350436)
		(end 86.280244 -272.625058)
		(width 0.088646)
		(layer "In4.Cu")
		(net "M_B_CPU1_SA_DQS_DP<6>")
	)
	(arc
		(start 88.997536 -272.143474)
		(mid 88.719104 -272.07366)
		(end 88.442292 -272.14957)
		(width 0.088646)
		(layer "In4.Cu")
		(net "M_B_CPU1_SA_DQS_DP<6>")
	)
	(arc
		(start 90.321892 -272.14957)
		(mid 90.134694 -272.199713)
		(end 89.947496 -272.14957)
		(width 0.088646)
		(layer "In4.Cu")
		(net "M_B_CPU1_SA_DQS_DP<6>")
	)
	(arc
		(start 89.947496 -272.14957)
		(mid 89.670937 -272.073861)
		(end 89.39276 -272.143474)
		(width 0.088646)
		(layer "In4.Cu")
		(net "M_B_CPU1_SA_DQS_DP<6>")
	)
	(arc
		(start 85.61705 -273.781012)
		(mid 85.414463 -273.987363)
		(end 85.340444 -274.266914)
		(width 0.088646)
		(layer "In4.Cu")
		(net "M_B_CPU1_SA_DQS_DP<6>")
	)
	(arc
		(start 87.113364 -272.140934)
		(mid 86.836923 -272.073768)
		(end 86.562692 -272.14957)
		(width 0.088646)
		(layer "In4.Cu")
		(net "M_B_CPU1_SA_DQS_DP<6>")
	)
	(arc
		(start 92.76715 -272.14957)
		(mid 92.492921 -272.073645)
		(end 92.216478 -272.140934)
		(width 0.088646)
		(layer "In4.Cu")
		(net "M_B_CPU1_SA_DQS_DP<6>")
	)
	(arc
		(start 89.382346 -272.14957)
		(mid 89.195148 -272.199713)
		(end 89.00795 -272.14957)
		(width 0.088646)
		(layer "In4.Cu")
		(net "M_B_CPU1_SA_DQS_DP<6>")
	)
	(arc
		(start 86.280244 -272.639282)
		(mid 86.232565 -272.822182)
		(end 86.101682 -272.95856)
		(width 0.088646)
		(layer "In4.Cu")
		(net "M_B_CPU1_SA_DQS_DP<6>")
	)
	(arc
		(start 87.502492 -272.14957)
		(mid 87.315294 -272.199713)
		(end 87.128096 -272.14957)
		(width 0.088646)
		(layer "In4.Cu")
		(net "M_B_CPU1_SA_DQS_DP<6>")
	)
	(segment
		(start 49.959514 -311.216802)
		(end 49.469548 -311.216802)
		(width 0.20066)
		(layer "F.Cu")
		(net "M_B_CPU1_SA_DQS_DP<5>")
	)
	(segment
		(start 43.485816 -311.477914)
		(end 43.151552 -311.477914)
		(width 0.20066)
		(layer "F.Cu")
		(net "M_B_CPU1_SA_DQS_DP<5>")
	)
	(segment
		(start 91.074748 -275.08073)
		(end 91.070938 -275.08073)
		(width 0.20066)
		(layer "F.Cu")
		(net "M_B_CPU1_SA_DQS_DP<5>")
	)
	(segment
		(start 49.208436 -311.477914)
		(end 48.603916 -311.477914)
		(width 0.20066)
		(layer "F.Cu")
		(net "M_B_CPU1_SA_DQS_DP<5>")
	)
	(segment
		(start 43.908218 -311.055512)
		(end 43.485816 -311.477914)
		(width 0.20066)
		(layer "F.Cu")
		(net "M_B_CPU1_SA_DQS_DP<5>")
	)
	(segment
		(start 44.26839 -311.055512)
		(end 43.908218 -311.055512)
		(width 0.20066)
		(layer "F.Cu")
		(net "M_B_CPU1_SA_DQS_DP<5>")
	)
	(segment
		(start 49.469548 -311.216802)
		(end 49.208436 -311.477914)
		(width 0.20066)
		(layer "F.Cu")
		(net "M_B_CPU1_SA_DQS_DP<5>")
	)
	(segment
		(start 47.201836 -310.79186)
		(end 47.060358 -310.79186)
		(width 0.20066)
		(layer "F.Cu")
		(net "M_B_CPU1_SA_DQS_DP<5>")
	)
	(segment
		(start 47.060358 -310.79186)
		(end 44.981876 -310.79186)
		(width 0.1016)
		(layer "F.Cu")
		(net "M_B_CPU1_SA_DQS_DP<5>")
	)
	(segment
		(start 91.070684 -274.54479)
		(end 91.074494 -274.54479)
		(width 0.20066)
		(layer "F.Cu")
		(net "M_B_CPU1_SA_DQS_DP<5>")
	)
	(segment
		(start 44.735242 -310.786018)
		(end 44.537884 -310.786018)
		(width 0.20066)
		(layer "F.Cu")
		(net "M_B_CPU1_SA_DQS_DP<5>")
	)
	(segment
		(start 44.981876 -310.79186)
		(end 44.741084 -310.79186)
		(width 0.101854)
		(layer "F.Cu")
		(net "M_B_CPU1_SA_DQS_DP<5>")
	)
	(segment
		(start 43.151552 -311.477914)
		(end 42.89044 -311.216802)
		(width 0.20066)
		(layer "F.Cu")
		(net "M_B_CPU1_SA_DQS_DP<5>")
	)
	(segment
		(start 51.089814 -311.216802)
		(end 49.959514 -311.216802)
		(width 0.20066)
		(layer "F.Cu")
		(net "M_B_CPU1_SA_DQS_DP<5>")
	)
	(segment
		(start 47.9679 -311.052972)
		(end 47.462948 -311.052972)
		(width 0.20066)
		(layer "F.Cu")
		(net "M_B_CPU1_SA_DQS_DP<5>")
	)
	(segment
		(start 42.89044 -311.216802)
		(end 42.415714 -311.216802)
		(width 0.20066)
		(layer "F.Cu")
		(net "M_B_CPU1_SA_DQS_DP<5>")
	)
	(segment
		(start 44.741084 -310.79186)
		(end 44.735242 -310.786018)
		(width 0.101854)
		(layer "F.Cu")
		(net "M_B_CPU1_SA_DQS_DP<5>")
	)
	(segment
		(start 47.462948 -311.052972)
		(end 47.201836 -310.79186)
		(width 0.20066)
		(layer "F.Cu")
		(net "M_B_CPU1_SA_DQS_DP<5>")
	)
	(segment
		(start 48.603916 -311.477914)
		(end 47.9679 -311.052972)
		(width 0.20066)
		(layer "F.Cu")
		(net "M_B_CPU1_SA_DQS_DP<5>")
	)
	(segment
		(start 44.537884 -310.786018)
		(end 44.26839 -311.055512)
		(width 0.20066)
		(layer "F.Cu")
		(net "M_B_CPU1_SA_DQS_DP<5>")
	)
	(arc
		(start 91.070938 -275.08073)
		(mid 91.070748 -274.81276)
		(end 91.070684 -274.54479)
		(width 0.20066)
		(layer "F.Cu")
		(net "M_B_CPU1_SA_DQS_DP<5>")
	)
	(segment
		(start 61.92774 -311.500266)
		(end 61.92774 -311.484518)
		(width 0.16002)
		(layer "In2.Cu")
		(net "M_B_CPU1_SA_DQS_DP<5>")
	)
	(segment
		(start 59.750452 -311.700418)
		(end 59.722258 -311.728612)
		(width 0.16002)
		(layer "In2.Cu")
		(net "M_B_CPU1_SA_DQS_DP<5>")
	)
	(segment
		(start 63.85052 -310.850534)
		(end 63.822326 -310.878728)
		(width 0.16002)
		(layer "In2.Cu")
		(net "M_B_CPU1_SA_DQS_DP<5>")
	)
	(segment
		(start 52.77485 -311.132474)
		(end 52.488846 -311.418478)
		(width 0.18288)
		(layer "In2.Cu")
		(net "M_B_CPU1_SA_DQS_DP<5>")
	)
	(segment
		(start 86.556596 -276.380702)
		(end 86.559898 -276.382734)
		(width 0.088646)
		(layer "In2.Cu")
		(net "M_B_CPU1_SA_DQS_DP<5>")
	)
	(segment
		(start 66.027808 -310.650382)
		(end 66.027808 -310.634634)
		(width 0.16002)
		(layer "In2.Cu")
		(net "M_B_CPU1_SA_DQS_DP<5>")
	)
	(segment
		(start 78.925166 -288.160968)
		(end 74.42962 -299.013626)
		(width 0.18288)
		(layer "In2.Cu")
		(net "M_B_CPU1_SA_DQS_DP<5>")
	)
	(segment
		(start 73.864978 -301.852584)
		(end 72.42429 -305.330098)
		(width 0.18288)
		(layer "In2.Cu")
		(net "M_B_CPU1_SA_DQS_DP<5>")
	)
	(segment
		(start 58.480706 -312.213752)
		(end 58.480706 -312.230008)
		(width 0.16002)
		(layer "In2.Cu")
		(net "M_B_CPU1_SA_DQS_DP<5>")
	)
	(segment
		(start 58.281062 -312.429652)
		(end 58.264806 -312.429652)
		(width 0.16002)
		(layer "In2.Cu")
		(net "M_B_CPU1_SA_DQS_DP<5>")
	)
	(segment
		(start 60.191904 -311.258966)
		(end 59.994546 -311.456324)
		(width 0.18288)
		(layer "In2.Cu")
		(net "M_B_CPU1_SA_DQS_DP<5>")
	)
	(segment
		(start 51.353466 -311.480454)
		(end 51.089814 -311.216802)
		(width 0.18288)
		(layer "In2.Cu")
		(net "M_B_CPU1_SA_DQS_DP<5>")
	)
	(segment
		(start 59.966352 -311.500266)
		(end 59.7662 -311.700418)
		(width 0.16002)
		(layer "In2.Cu")
		(net "M_B_CPU1_SA_DQS_DP<5>")
	)
	(segment
		(start 86.5632 -275.40458)
		(end 86.562438 -275.405088)
		(width 0.088646)
		(layer "In2.Cu")
		(net "M_B_CPU1_SA_DQS_DP<5>")
	)
	(segment
		(start 56.21782 -311.90565)
		(end 54.804818 -311.90565)
		(width 0.18288)
		(layer "In2.Cu")
		(net "M_B_CPU1_SA_DQS_DP<5>")
	)
	(segment
		(start 86.571582 -276.389592)
		(end 86.571582 -276.389338)
		(width 0.088646)
		(layer "In2.Cu")
		(net "M_B_CPU1_SA_DQS_DP<5>")
	)
	(segment
		(start 86.27999 -277.508462)
		(end 86.27999 -277.522686)
		(width 0.088646)
		(layer "In2.Cu")
		(net "M_B_CPU1_SA_DQS_DP<5>")
	)
	(segment
		(start 61.92774 -311.484518)
		(end 61.899546 -311.456324)
		(width 0.16002)
		(layer "In2.Cu")
		(net "M_B_CPU1_SA_DQS_DP<5>")
	)
	(segment
		(start 86.563454 -276.384766)
		(end 86.571582 -276.389592)
		(width 0.088646)
		(layer "In2.Cu")
		(net "M_B_CPU1_SA_DQS_DP<5>")
	)
	(segment
		(start 82.440272 -283.613352)
		(end 81.710276 -285.375604)
		(width 0.18288)
		(layer "In2.Cu")
		(net "M_B_CPU1_SA_DQS_DP<5>")
	)
	(segment
		(start 62.290452 -311.84723)
		(end 62.171834 -311.728612)
		(width 0.18288)
		(layer "In2.Cu")
		(net "M_B_CPU1_SA_DQS_DP<5>")
	)
	(segment
		(start 64.094614 -310.60644)
		(end 64.06642 -310.634634)
		(width 0.16002)
		(layer "In2.Cu")
		(net "M_B_CPU1_SA_DQS_DP<5>")
	)
	(segment
		(start 54.804818 -311.90565)
		(end 54.628034 -311.728866)
		(width 0.18288)
		(layer "In2.Cu")
		(net "M_B_CPU1_SA_DQS_DP<5>")
	)
	(segment
		(start 56.876696 -312.564526)
		(end 56.770016 -312.457846)
		(width 0.18288)
		(layer "In2.Cu")
		(net "M_B_CPU1_SA_DQS_DP<5>")
	)
	(segment
		(start 58.129932 -312.564526)
		(end 56.876696 -312.564526)
		(width 0.18288)
		(layer "In2.Cu")
		(net "M_B_CPU1_SA_DQS_DP<5>")
	)
	(segment
		(start 66.623184 -310.98744)
		(end 66.380614 -310.98744)
		(width 0.18288)
		(layer "In2.Cu")
		(net "M_B_CPU1_SA_DQS_DP<5>")
	)
	(segment
		(start 62.171834 -311.728612)
		(end 62.14364 -311.700418)
		(width 0.16002)
		(layer "In2.Cu")
		(net "M_B_CPU1_SA_DQS_DP<5>")
	)
	(segment
		(start 91.074748 -275.08073)
		(end 90.762074 -275.08073)
		(width 0.088646)
		(layer "In2.Cu")
		(net "M_B_CPU1_SA_DQS_DP<5>")
	)
	(segment
		(start 86.571328 -275.400008)
		(end 86.5632 -275.40458)
		(width 0.088646)
		(layer "In2.Cu")
		(net "M_B_CPU1_SA_DQS_DP<5>")
	)
	(segment
		(start 56.725566 -312.429652)
		(end 56.525922 -312.230008)
		(width 0.16002)
		(layer "In2.Cu")
		(net "M_B_CPU1_SA_DQS_DP<5>")
	)
	(segment
		(start 86.74989 -275.072856)
		(end 86.74989 -275.08073)
		(width 0.088646)
		(layer "In2.Cu")
		(net "M_B_CPU1_SA_DQS_DP<5>")
	)
	(segment
		(start 64.06642 -310.634634)
		(end 64.06642 -310.650382)
		(width 0.16002)
		(layer "In2.Cu")
		(net "M_B_CPU1_SA_DQS_DP<5>")
	)
	(segment
		(start 81.710276 -285.375604)
		(end 78.925166 -288.160968)
		(width 0.18288)
		(layer "In2.Cu")
		(net "M_B_CPU1_SA_DQS_DP<5>")
	)
	(segment
		(start 54.584092 -311.700672)
		(end 54.38394 -311.50052)
		(width 0.16002)
		(layer "In2.Cu")
		(net "M_B_CPU1_SA_DQS_DP<5>")
	)
	(segment
		(start 52.180744 -311.72658)
		(end 51.898296 -311.72658)
		(width 0.18288)
		(layer "In2.Cu")
		(net "M_B_CPU1_SA_DQS_DP<5>")
	)
	(segment
		(start 85.754972 -278.711406)
		(end 85.37575 -279.090628)
		(width 0.088646)
		(layer "In2.Cu")
		(net "M_B_CPU1_SA_DQS_DP<5>")
	)
	(segment
		(start 66.22796 -310.850534)
		(end 66.027808 -310.650382)
		(width 0.16002)
		(layer "In2.Cu")
		(net "M_B_CPU1_SA_DQS_DP<5>")
	)
	(segment
		(start 85.37575 -279.090628)
		(end 84.950808 -279.090628)
		(width 0.088646)
		(layer "In2.Cu")
		(net "M_B_CPU1_SA_DQS_DP<5>")
	)
	(segment
		(start 72.42429 -305.330098)
		(end 66.868294 -310.88584)
		(width 0.18288)
		(layer "In2.Cu")
		(net "M_B_CPU1_SA_DQS_DP<5>")
	)
	(segment
		(start 62.853824 -311.84723)
		(end 62.290452 -311.84723)
		(width 0.18288)
		(layer "In2.Cu")
		(net "M_B_CPU1_SA_DQS_DP<5>")
	)
	(segment
		(start 82.549238 -281.40787)
		(end 82.549238 -283.350462)
		(width 0.18288)
		(layer "In2.Cu")
		(net "M_B_CPU1_SA_DQS_DP<5>")
	)
	(segment
		(start 54.355746 -311.456578)
		(end 54.031642 -311.132474)
		(width 0.18288)
		(layer "In2.Cu")
		(net "M_B_CPU1_SA_DQS_DP<5>")
	)
	(segment
		(start 65.802256 -310.409082)
		(end 64.291972 -310.409082)
		(width 0.18288)
		(layer "In2.Cu")
		(net "M_B_CPU1_SA_DQS_DP<5>")
	)
	(segment
		(start 74.42962 -299.013626)
		(end 73.864978 -301.852584)
		(width 0.18288)
		(layer "In2.Cu")
		(net "M_B_CPU1_SA_DQS_DP<5>")
	)
	(segment
		(start 56.525922 -312.230008)
		(end 56.525922 -312.213752)
		(width 0.16002)
		(layer "In2.Cu")
		(net "M_B_CPU1_SA_DQS_DP<5>")
	)
	(segment
		(start 54.031642 -311.132474)
		(end 52.77485 -311.132474)
		(width 0.18288)
		(layer "In2.Cu")
		(net "M_B_CPU1_SA_DQS_DP<5>")
	)
	(segment
		(start 63.866268 -310.850534)
		(end 63.85052 -310.850534)
		(width 0.16002)
		(layer "In2.Cu")
		(net "M_B_CPU1_SA_DQS_DP<5>")
	)
	(segment
		(start 51.898296 -311.72658)
		(end 51.65217 -311.480454)
		(width 0.18288)
		(layer "In2.Cu")
		(net "M_B_CPU1_SA_DQS_DP<5>")
	)
	(segment
		(start 61.899546 -311.456324)
		(end 61.702188 -311.258966)
		(width 0.18288)
		(layer "In2.Cu")
		(net "M_B_CPU1_SA_DQS_DP<5>")
	)
	(segment
		(start 62.127892 -311.700418)
		(end 61.92774 -311.500266)
		(width 0.16002)
		(layer "In2.Cu")
		(net "M_B_CPU1_SA_DQS_DP<5>")
	)
	(segment
		(start 66.380614 -310.98744)
		(end 66.271902 -310.878728)
		(width 0.18288)
		(layer "In2.Cu")
		(net "M_B_CPU1_SA_DQS_DP<5>")
	)
	(segment
		(start 58.480706 -312.230008)
		(end 58.281062 -312.429652)
		(width 0.16002)
		(layer "In2.Cu")
		(net "M_B_CPU1_SA_DQS_DP<5>")
	)
	(segment
		(start 84.64931 -279.307798)
		(end 82.549238 -281.40787)
		(width 0.18288)
		(layer "In2.Cu")
		(net "M_B_CPU1_SA_DQS_DP<5>")
	)
	(segment
		(start 52.460652 -311.446672)
		(end 52.460652 -311.46242)
		(width 0.16002)
		(layer "In2.Cu")
		(net "M_B_CPU1_SA_DQS_DP<5>")
	)
	(segment
		(start 54.628034 -311.728866)
		(end 54.59984 -311.700672)
		(width 0.16002)
		(layer "In2.Cu")
		(net "M_B_CPU1_SA_DQS_DP<5>")
	)
	(segment
		(start 82.549238 -283.350462)
		(end 82.440272 -283.613352)
		(width 0.18288)
		(layer "In2.Cu")
		(net "M_B_CPU1_SA_DQS_DP<5>")
	)
	(segment
		(start 86.559898 -276.382734)
		(end 86.562692 -276.384258)
		(width 0.088646)
		(layer "In2.Cu")
		(net "M_B_CPU1_SA_DQS_DP<5>")
	)
	(segment
		(start 54.59984 -311.700672)
		(end 54.584092 -311.700672)
		(width 0.16002)
		(layer "In2.Cu")
		(net "M_B_CPU1_SA_DQS_DP<5>")
	)
	(segment
		(start 56.770016 -312.457846)
		(end 56.741822 -312.429652)
		(width 0.16002)
		(layer "In2.Cu")
		(net "M_B_CPU1_SA_DQS_DP<5>")
	)
	(segment
		(start 52.244752 -311.662572)
		(end 52.216558 -311.690766)
		(width 0.16002)
		(layer "In2.Cu")
		(net "M_B_CPU1_SA_DQS_DP<5>")
	)
	(segment
		(start 58.236612 -312.457846)
		(end 58.129932 -312.564526)
		(width 0.18288)
		(layer "In2.Cu")
		(net "M_B_CPU1_SA_DQS_DP<5>")
	)
	(segment
		(start 56.525922 -312.213752)
		(end 56.497728 -312.185558)
		(width 0.16002)
		(layer "In2.Cu")
		(net "M_B_CPU1_SA_DQS_DP<5>")
	)
	(segment
		(start 58.5089 -312.185558)
		(end 58.480706 -312.213752)
		(width 0.16002)
		(layer "In2.Cu")
		(net "M_B_CPU1_SA_DQS_DP<5>")
	)
	(segment
		(start 63.822326 -310.878728)
		(end 62.853824 -311.84723)
		(width 0.18288)
		(layer "In2.Cu")
		(net "M_B_CPU1_SA_DQS_DP<5>")
	)
	(segment
		(start 86.556596 -278.008588)
		(end 86.571582 -278.017224)
		(width 0.088646)
		(layer "In2.Cu")
		(net "M_B_CPU1_SA_DQS_DP<5>")
	)
	(segment
		(start 52.488846 -311.418478)
		(end 52.460652 -311.446672)
		(width 0.16002)
		(layer "In2.Cu")
		(net "M_B_CPU1_SA_DQS_DP<5>")
	)
	(segment
		(start 54.38394 -311.50052)
		(end 54.38394 -311.484772)
		(width 0.16002)
		(layer "In2.Cu")
		(net "M_B_CPU1_SA_DQS_DP<5>")
	)
	(segment
		(start 86.571582 -278.65578)
		(end 86.562692 -278.66086)
		(width 0.088646)
		(layer "In2.Cu")
		(net "M_B_CPU1_SA_DQS_DP<5>")
	)
	(segment
		(start 64.06642 -310.650382)
		(end 63.866268 -310.850534)
		(width 0.16002)
		(layer "In2.Cu")
		(net "M_B_CPU1_SA_DQS_DP<5>")
	)
	(segment
		(start 59.563 -311.88787)
		(end 58.806588 -311.88787)
		(width 0.18288)
		(layer "In2.Cu")
		(net "M_B_CPU1_SA_DQS_DP<5>")
	)
	(segment
		(start 62.14364 -311.700418)
		(end 62.127892 -311.700418)
		(width 0.16002)
		(layer "In2.Cu")
		(net "M_B_CPU1_SA_DQS_DP<5>")
	)
	(segment
		(start 52.460652 -311.46242)
		(end 52.2605 -311.662572)
		(width 0.16002)
		(layer "In2.Cu")
		(net "M_B_CPU1_SA_DQS_DP<5>")
	)
	(segment
		(start 59.7662 -311.700418)
		(end 59.750452 -311.700418)
		(width 0.16002)
		(layer "In2.Cu")
		(net "M_B_CPU1_SA_DQS_DP<5>")
	)
	(segment
		(start 86.375494 -278.711406)
		(end 85.754972 -278.711406)
		(width 0.088646)
		(layer "In2.Cu")
		(net "M_B_CPU1_SA_DQS_DP<5>")
	)
	(segment
		(start 51.65217 -311.480454)
		(end 51.353466 -311.480454)
		(width 0.18288)
		(layer "In2.Cu")
		(net "M_B_CPU1_SA_DQS_DP<5>")
	)
	(segment
		(start 66.868294 -310.88584)
		(end 66.623184 -310.98744)
		(width 0.18288)
		(layer "In2.Cu")
		(net "M_B_CPU1_SA_DQS_DP<5>")
	)
	(segment
		(start 61.702188 -311.258966)
		(end 60.191904 -311.258966)
		(width 0.18288)
		(layer "In2.Cu")
		(net "M_B_CPU1_SA_DQS_DP<5>")
	)
	(segment
		(start 56.741822 -312.429652)
		(end 56.725566 -312.429652)
		(width 0.16002)
		(layer "In2.Cu")
		(net "M_B_CPU1_SA_DQS_DP<5>")
	)
	(segment
		(start 64.291972 -310.409082)
		(end 64.094614 -310.60644)
		(width 0.18288)
		(layer "In2.Cu")
		(net "M_B_CPU1_SA_DQS_DP<5>")
	)
	(segment
		(start 86.571582 -277.027894)
		(end 86.562692 -277.032974)
		(width 0.088646)
		(layer "In2.Cu")
		(net "M_B_CPU1_SA_DQS_DP<5>")
	)
	(segment
		(start 66.027808 -310.634634)
		(end 65.999614 -310.60644)
		(width 0.16002)
		(layer "In2.Cu")
		(net "M_B_CPU1_SA_DQS_DP<5>")
	)
	(segment
		(start 84.950808 -279.090628)
		(end 84.733638 -279.307798)
		(width 0.088646)
		(layer "In2.Cu")
		(net "M_B_CPU1_SA_DQS_DP<5>")
	)
	(segment
		(start 54.38394 -311.484772)
		(end 54.355746 -311.456578)
		(width 0.16002)
		(layer "In2.Cu")
		(net "M_B_CPU1_SA_DQS_DP<5>")
	)
	(segment
		(start 59.994546 -311.456324)
		(end 59.966352 -311.484518)
		(width 0.16002)
		(layer "In2.Cu")
		(net "M_B_CPU1_SA_DQS_DP<5>")
	)
	(segment
		(start 86.27999 -275.876258)
		(end 86.27999 -275.8948)
		(width 0.088646)
		(layer "In2.Cu")
		(net "M_B_CPU1_SA_DQS_DP<5>")
	)
	(segment
		(start 87.047324 -274.582636)
		(end 87.032592 -274.591272)
		(width 0.088646)
		(layer "In2.Cu")
		(net "M_B_CPU1_SA_DQS_DP<5>")
	)
	(segment
		(start 56.497728 -312.185558)
		(end 56.21782 -311.90565)
		(width 0.18288)
		(layer "In2.Cu")
		(net "M_B_CPU1_SA_DQS_DP<5>")
	)
	(segment
		(start 59.966352 -311.484518)
		(end 59.966352 -311.500266)
		(width 0.16002)
		(layer "In2.Cu")
		(net "M_B_CPU1_SA_DQS_DP<5>")
	)
	(segment
		(start 90.762074 -275.08073)
		(end 90.696288 -275.014944)
		(width 0.088646)
		(layer "In2.Cu")
		(net "M_B_CPU1_SA_DQS_DP<5>")
	)
	(segment
		(start 66.243708 -310.850534)
		(end 66.22796 -310.850534)
		(width 0.16002)
		(layer "In2.Cu")
		(net "M_B_CPU1_SA_DQS_DP<5>")
	)
	(segment
		(start 52.2605 -311.662572)
		(end 52.244752 -311.662572)
		(width 0.16002)
		(layer "In2.Cu")
		(net "M_B_CPU1_SA_DQS_DP<5>")
	)
	(segment
		(start 52.216558 -311.690766)
		(end 52.180744 -311.72658)
		(width 0.18288)
		(layer "In2.Cu")
		(net "M_B_CPU1_SA_DQS_DP<5>")
	)
	(segment
		(start 84.733638 -279.307798)
		(end 84.64931 -279.307798)
		(width 0.088646)
		(layer "In2.Cu")
		(net "M_B_CPU1_SA_DQS_DP<5>")
	)
	(segment
		(start 86.562692 -276.384258)
		(end 86.563454 -276.384766)
		(width 0.088646)
		(layer "In2.Cu")
		(net "M_B_CPU1_SA_DQS_DP<5>")
	)
	(segment
		(start 66.271902 -310.878728)
		(end 66.243708 -310.850534)
		(width 0.16002)
		(layer "In2.Cu")
		(net "M_B_CPU1_SA_DQS_DP<5>")
	)
	(segment
		(start 58.806588 -311.88787)
		(end 58.5089 -312.185558)
		(width 0.18288)
		(layer "In2.Cu")
		(net "M_B_CPU1_SA_DQS_DP<5>")
	)
	(segment
		(start 59.722258 -311.728612)
		(end 59.563 -311.88787)
		(width 0.18288)
		(layer "In2.Cu")
		(net "M_B_CPU1_SA_DQS_DP<5>")
	)
	(segment
		(start 65.999614 -310.60644)
		(end 65.802256 -310.409082)
		(width 0.18288)
		(layer "In2.Cu")
		(net "M_B_CPU1_SA_DQS_DP<5>")
	)
	(segment
		(start 58.264806 -312.429652)
		(end 58.236612 -312.457846)
		(width 0.16002)
		(layer "In2.Cu")
		(net "M_B_CPU1_SA_DQS_DP<5>")
	)
	(arc
		(start 89.477596 -274.591272)
		(mid 89.194894 -274.515496)
		(end 88.912192 -274.591272)
		(width 0.088646)
		(layer "In2.Cu")
		(net "M_B_CPU1_SA_DQS_DP<5>")
	)
	(arc
		(start 89.851992 -274.591272)
		(mid 89.664794 -274.641415)
		(end 89.477596 -274.591272)
		(width 0.088646)
		(layer "In2.Cu")
		(net "M_B_CPU1_SA_DQS_DP<5>")
	)
	(arc
		(start 86.27999 -277.522686)
		(mid 86.353981 -277.802252)
		(end 86.556596 -278.008588)
		(width 0.088646)
		(layer "In2.Cu")
		(net "M_B_CPU1_SA_DQS_DP<5>")
	)
	(arc
		(start 86.562692 -277.032974)
		(mid 86.359211 -277.233778)
		(end 86.27999 -277.508462)
		(width 0.088646)
		(layer "In2.Cu")
		(net "M_B_CPU1_SA_DQS_DP<5>")
	)
	(arc
		(start 87.597996 -274.591272)
		(mid 87.323797 -274.515437)
		(end 87.047324 -274.582636)
		(width 0.088646)
		(layer "In2.Cu")
		(net "M_B_CPU1_SA_DQS_DP<5>")
	)
	(arc
		(start 90.693494 -274.994116)
		(mid 90.378896 -274.570916)
		(end 89.851992 -274.591272)
		(width 0.088646)
		(layer "In2.Cu")
		(net "M_B_CPU1_SA_DQS_DP<5>")
	)
	(arc
		(start 86.27999 -275.8948)
		(mid 86.353981 -276.174366)
		(end 86.556596 -276.380702)
		(width 0.088646)
		(layer "In2.Cu")
		(net "M_B_CPU1_SA_DQS_DP<5>")
	)
	(arc
		(start 87.032592 -274.591272)
		(mid 86.827654 -274.794722)
		(end 86.74989 -275.072856)
		(width 0.088646)
		(layer "In2.Cu")
		(net "M_B_CPU1_SA_DQS_DP<5>")
	)
	(arc
		(start 90.696288 -275.014944)
		(mid 90.694987 -275.004517)
		(end 90.693494 -274.994116)
		(width 0.088646)
		(layer "In2.Cu")
		(net "M_B_CPU1_SA_DQS_DP<5>")
	)
	(arc
		(start 88.537796 -274.591272)
		(mid 88.255094 -274.515496)
		(end 87.972392 -274.591272)
		(width 0.088646)
		(layer "In2.Cu")
		(net "M_B_CPU1_SA_DQS_DP<5>")
	)
	(arc
		(start 86.74989 -275.08073)
		(mid 86.702211 -275.26363)
		(end 86.571328 -275.400008)
		(width 0.088646)
		(layer "In2.Cu")
		(net "M_B_CPU1_SA_DQS_DP<5>")
	)
	(arc
		(start 86.571582 -278.017224)
		(mid 86.750179 -278.336502)
		(end 86.571582 -278.65578)
		(width 0.088646)
		(layer "In2.Cu")
		(net "M_B_CPU1_SA_DQS_DP<5>")
	)
	(arc
		(start 88.912192 -274.591272)
		(mid 88.724994 -274.641415)
		(end 88.537796 -274.591272)
		(width 0.088646)
		(layer "In2.Cu")
		(net "M_B_CPU1_SA_DQS_DP<5>")
	)
	(arc
		(start 87.972392 -274.591272)
		(mid 87.785194 -274.641415)
		(end 87.597996 -274.591272)
		(width 0.088646)
		(layer "In2.Cu")
		(net "M_B_CPU1_SA_DQS_DP<5>")
	)
	(arc
		(start 86.562692 -278.66086)
		(mid 86.47242 -278.698459)
		(end 86.375494 -278.711406)
		(width 0.088646)
		(layer "In2.Cu")
		(net "M_B_CPU1_SA_DQS_DP<5>")
	)
	(arc
		(start 86.562438 -275.405088)
		(mid 86.360152 -275.604069)
		(end 86.27999 -275.876258)
		(width 0.088646)
		(layer "In2.Cu")
		(net "M_B_CPU1_SA_DQS_DP<5>")
	)
	(arc
		(start 86.571582 -276.389338)
		(mid 86.750179 -276.708616)
		(end 86.571582 -277.027894)
		(width 0.088646)
		(layer "In2.Cu")
		(net "M_B_CPU1_SA_DQS_DP<5>")
	)
	(segment
		(start 43.768772 -275.94179)
		(end 43.616626 -275.94179)
		(width 0.20066)
		(layer "F.Cu")
		(net "M_B_CPU1_SA_DQS_DP<4>")
	)
	(segment
		(start 40.802814 -275.680678)
		(end 40.175688 -275.680678)
		(width 0.20066)
		(layer "F.Cu")
		(net "M_B_CPU1_SA_DQS_DP<4>")
	)
	(segment
		(start 89.184226 -259.894832)
		(end 89.194894 -259.894832)
		(width 0.20066)
		(layer "F.Cu")
		(net "M_B_CPU1_SA_DQS_DP<4>")
	)
	(segment
		(start 46.964346 -275.516594)
		(end 45.859446 -275.516594)
		(width 0.20066)
		(layer "F.Cu")
		(net "M_B_CPU1_SA_DQS_DP<4>")
	)
	(segment
		(start 39.11473 -275.255482)
		(end 38.853618 -275.516594)
		(width 0.20066)
		(layer "F.Cu")
		(net "M_B_CPU1_SA_DQS_DP<4>")
	)
	(segment
		(start 89.195148 -260.430772)
		(end 89.18448 -260.430772)
		(width 0.20066)
		(layer "F.Cu")
		(net "M_B_CPU1_SA_DQS_DP<4>")
	)
	(segment
		(start 39.539672 -275.255482)
		(end 39.11473 -275.255482)
		(width 0.20066)
		(layer "F.Cu")
		(net "M_B_CPU1_SA_DQS_DP<4>")
	)
	(segment
		(start 41.073324 -275.951188)
		(end 40.802814 -275.680678)
		(width 0.20066)
		(layer "F.Cu")
		(net "M_B_CPU1_SA_DQS_DP<4>")
	)
	(segment
		(start 43.616626 -275.94179)
		(end 43.293284 -275.94179)
		(width 0.101854)
		(layer "F.Cu")
		(net "M_B_CPU1_SA_DQS_DP<4>")
	)
	(segment
		(start 40.175688 -275.680678)
		(end 39.539672 -275.255482)
		(width 0.20066)
		(layer "F.Cu")
		(net "M_B_CPU1_SA_DQS_DP<4>")
	)
	(segment
		(start 45.859446 -275.516594)
		(end 45.310806 -275.516594)
		(width 0.20066)
		(layer "F.Cu")
		(net "M_B_CPU1_SA_DQS_DP<4>")
	)
	(segment
		(start 38.853618 -275.516594)
		(end 38.315646 -275.516594)
		(width 0.20066)
		(layer "F.Cu")
		(net "M_B_CPU1_SA_DQS_DP<4>")
	)
	(segment
		(start 45.049694 -275.255482)
		(end 44.780962 -275.255482)
		(width 0.20066)
		(layer "F.Cu")
		(net "M_B_CPU1_SA_DQS_DP<4>")
	)
	(segment
		(start 43.293284 -275.94179)
		(end 41.53789 -275.94179)
		(width 0.1016)
		(layer "F.Cu")
		(net "M_B_CPU1_SA_DQS_DP<4>")
	)
	(segment
		(start 41.300908 -275.94179)
		(end 41.29151 -275.951188)
		(width 0.101854)
		(layer "F.Cu")
		(net "M_B_CPU1_SA_DQS_DP<4>")
	)
	(segment
		(start 41.53789 -275.94179)
		(end 41.300908 -275.94179)
		(width 0.101854)
		(layer "F.Cu")
		(net "M_B_CPU1_SA_DQS_DP<4>")
	)
	(segment
		(start 45.310806 -275.516594)
		(end 45.049694 -275.255482)
		(width 0.20066)
		(layer "F.Cu")
		(net "M_B_CPU1_SA_DQS_DP<4>")
	)
	(segment
		(start 44.029884 -275.680678)
		(end 43.768772 -275.94179)
		(width 0.20066)
		(layer "F.Cu")
		(net "M_B_CPU1_SA_DQS_DP<4>")
	)
	(segment
		(start 41.29151 -275.951188)
		(end 41.073324 -275.951188)
		(width 0.20066)
		(layer "F.Cu")
		(net "M_B_CPU1_SA_DQS_DP<4>")
	)
	(segment
		(start 44.780962 -275.255482)
		(end 44.355766 -275.680678)
		(width 0.20066)
		(layer "F.Cu")
		(net "M_B_CPU1_SA_DQS_DP<4>")
	)
	(segment
		(start 44.355766 -275.680678)
		(end 44.029884 -275.680678)
		(width 0.20066)
		(layer "F.Cu")
		(net "M_B_CPU1_SA_DQS_DP<4>")
	)
	(arc
		(start 89.18448 -260.430772)
		(mid 89.18417 -260.162802)
		(end 89.184226 -259.894832)
		(width 0.20066)
		(layer "F.Cu")
		(net "M_B_CPU1_SA_DQS_DP<4>")
	)
	(segment
		(start 84.025994 -260.869684)
		(end 83.710018 -260.869684)
		(width 0.088646)
		(layer "In2.Cu")
		(net "M_B_CPU1_SA_DQS_DP<4>")
	)
	(segment
		(start 48.895 -275.169884)
		(end 48.866806 -275.14169)
		(width 0.16002)
		(layer "In2.Cu")
		(net "M_B_CPU1_SA_DQS_DP<4>")
	)
	(segment
		(start 89.195148 -260.430772)
		(end 88.817196 -260.431026)
		(width 0.088646)
		(layer "In2.Cu")
		(net "M_B_CPU1_SA_DQS_DP<4>")
	)
	(segment
		(start 60.207906 -276.329902)
		(end 60.002166 -276.124162)
		(width 0.18288)
		(layer "In2.Cu")
		(net "M_B_CPU1_SA_DQS_DP<4>")
	)
	(segment
		(start 62.47638 -275.539708)
		(end 62.164214 -275.851874)
		(width 0.18288)
		(layer "In2.Cu")
		(net "M_B_CPU1_SA_DQS_DP<4>")
	)
	(segment
		(start 52.186078 -275.851874)
		(end 51.993292 -275.659088)
		(width 0.18288)
		(layer "In2.Cu")
		(net "M_B_CPU1_SA_DQS_DP<4>")
	)
	(segment
		(start 54.37632 -276.08022)
		(end 54.37632 -276.095968)
		(width 0.16002)
		(layer "In2.Cu")
		(net "M_B_CPU1_SA_DQS_DP<4>")
	)
	(segment
		(start 66.647314 -273.74723)
		(end 66.099436 -273.74723)
		(width 0.18288)
		(layer "In2.Cu")
		(net "M_B_CPU1_SA_DQS_DP<4>")
	)
	(segment
		(start 64.115188 -273.566636)
		(end 64.115188 -273.582892)
		(width 0.16002)
		(layer "In2.Cu")
		(net "M_B_CPU1_SA_DQS_DP<4>")
	)
	(segment
		(start 64.328548 -273.369532)
		(end 64.312292 -273.369532)
		(width 0.16002)
		(layer "In2.Cu")
		(net "M_B_CPU1_SA_DQS_DP<4>")
	)
	(segment
		(start 88.817196 -260.431026)
		(end 88.536018 -260.712204)
		(width 0.088646)
		(layer "In2.Cu")
		(net "M_B_CPU1_SA_DQS_DP<4>")
	)
	(segment
		(start 52.430172 -276.08022)
		(end 52.23002 -275.880068)
		(width 0.16002)
		(layer "In2.Cu")
		(net "M_B_CPU1_SA_DQS_DP<4>")
	)
	(segment
		(start 62.120272 -275.880068)
		(end 61.92012 -276.08022)
		(width 0.16002)
		(layer "In2.Cu")
		(net "M_B_CPU1_SA_DQS_DP<4>")
	)
	(segment
		(start 61.891926 -276.124162)
		(end 61.686186 -276.329902)
		(width 0.18288)
		(layer "In2.Cu")
		(net "M_B_CPU1_SA_DQS_DP<4>")
	)
	(segment
		(start 48.866806 -275.14169)
		(end 48.691546 -274.96643)
		(width 0.18288)
		(layer "In2.Cu")
		(net "M_B_CPU1_SA_DQS_DP<4>")
	)
	(segment
		(start 59.77382 -275.880068)
		(end 59.758072 -275.880068)
		(width 0.16002)
		(layer "In2.Cu")
		(net "M_B_CPU1_SA_DQS_DP<4>")
	)
	(segment
		(start 65.484756 -273.13255)
		(end 64.56553 -273.13255)
		(width 0.18288)
		(layer "In2.Cu")
		(net "M_B_CPU1_SA_DQS_DP<4>")
	)
	(segment
		(start 54.815232 -275.657056)
		(end 54.620414 -275.851874)
		(width 0.18288)
		(layer "In2.Cu")
		(net "M_B_CPU1_SA_DQS_DP<4>")
	)
	(segment
		(start 50.86985 -275.94179)
		(end 50.590958 -275.662898)
		(width 0.18288)
		(layer "In2.Cu")
		(net "M_B_CPU1_SA_DQS_DP<4>")
	)
	(segment
		(start 58.784998 -275.943314)
		(end 58.43143 -275.943314)
		(width 0.18288)
		(layer "In2.Cu")
		(net "M_B_CPU1_SA_DQS_DP<4>")
	)
	(segment
		(start 52.639214 -276.30501)
		(end 52.458366 -276.124162)
		(width 0.18288)
		(layer "In2.Cu")
		(net "M_B_CPU1_SA_DQS_DP<4>")
	)
	(segment
		(start 56.95569 -275.671534)
		(end 56.682894 -275.398738)
		(width 0.18288)
		(layer "In2.Cu")
		(net "M_B_CPU1_SA_DQS_DP<4>")
	)
	(segment
		(start 64.356742 -273.341338)
		(end 64.328548 -273.369532)
		(width 0.16002)
		(layer "In2.Cu")
		(net "M_B_CPU1_SA_DQS_DP<4>")
	)
	(segment
		(start 88.225376 -260.804406)
		(end 88.224868 -260.804914)
		(width 0.088646)
		(layer "In2.Cu")
		(net "M_B_CPU1_SA_DQS_DP<4>")
	)
	(segment
		(start 51.54168 -275.659088)
		(end 51.258978 -275.94179)
		(width 0.18288)
		(layer "In2.Cu")
		(net "M_B_CPU1_SA_DQS_DP<4>")
	)
	(segment
		(start 81.022698 -263.014206)
		(end 79.057754 -263.014206)
		(width 0.18288)
		(layer "In2.Cu")
		(net "M_B_CPU1_SA_DQS_DP<4>")
	)
	(segment
		(start 56.6547 -275.354796)
		(end 56.454548 -275.154644)
		(width 0.16002)
		(layer "In2.Cu")
		(net "M_B_CPU1_SA_DQS_DP<4>")
	)
	(segment
		(start 50.590958 -275.662898)
		(end 49.388014 -275.662898)
		(width 0.18288)
		(layer "In2.Cu")
		(net "M_B_CPU1_SA_DQS_DP<4>")
	)
	(segment
		(start 81.046066 -263.014206)
		(end 81.022698 -263.014206)
		(width 0.088646)
		(layer "In2.Cu")
		(net "M_B_CPU1_SA_DQS_DP<4>")
	)
	(segment
		(start 65.695322 -273.32686)
		(end 65.679066 -273.32686)
		(width 0.16002)
		(layer "In2.Cu")
		(net "M_B_CPU1_SA_DQS_DP<4>")
	)
	(segment
		(start 56.6547 -275.370544)
		(end 56.6547 -275.354796)
		(width 0.16002)
		(layer "In2.Cu")
		(net "M_B_CPU1_SA_DQS_DP<4>")
	)
	(segment
		(start 51.258978 -275.94179)
		(end 50.86985 -275.94179)
		(width 0.18288)
		(layer "In2.Cu")
		(net "M_B_CPU1_SA_DQS_DP<4>")
	)
	(segment
		(start 61.92012 -276.095968)
		(end 61.891926 -276.124162)
		(width 0.16002)
		(layer "In2.Cu")
		(net "M_B_CPU1_SA_DQS_DP<4>")
	)
	(segment
		(start 47.18685 -275.29409)
		(end 46.964346 -275.516594)
		(width 0.18288)
		(layer "In2.Cu")
		(net "M_B_CPU1_SA_DQS_DP<4>")
	)
	(segment
		(start 54.59222 -275.880068)
		(end 54.576472 -275.880068)
		(width 0.16002)
		(layer "In2.Cu")
		(net "M_B_CPU1_SA_DQS_DP<4>")
	)
	(segment
		(start 56.311546 -275.02739)
		(end 56.017668 -275.02739)
		(width 0.18288)
		(layer "In2.Cu")
		(net "M_B_CPU1_SA_DQS_DP<4>")
	)
	(segment
		(start 64.312292 -273.369532)
		(end 64.115188 -273.566636)
		(width 0.16002)
		(layer "In2.Cu")
		(net "M_B_CPU1_SA_DQS_DP<4>")
	)
	(segment
		(start 48.691546 -274.96643)
		(end 48.173386 -274.96643)
		(width 0.18288)
		(layer "In2.Cu")
		(net "M_B_CPU1_SA_DQS_DP<4>")
	)
	(segment
		(start 56.4388 -275.154644)
		(end 56.410606 -275.12645)
		(width 0.16002)
		(layer "In2.Cu")
		(net "M_B_CPU1_SA_DQS_DP<4>")
	)
	(segment
		(start 62.13602 -275.880068)
		(end 62.120272 -275.880068)
		(width 0.16002)
		(layer "In2.Cu")
		(net "M_B_CPU1_SA_DQS_DP<4>")
	)
	(segment
		(start 65.92316 -273.570954)
		(end 65.894966 -273.54276)
		(width 0.16002)
		(layer "In2.Cu")
		(net "M_B_CPU1_SA_DQS_DP<4>")
	)
	(segment
		(start 49.139094 -275.413978)
		(end 49.1109 -275.385784)
		(width 0.16002)
		(layer "In2.Cu")
		(net "M_B_CPU1_SA_DQS_DP<4>")
	)
	(segment
		(start 52.23002 -275.880068)
		(end 52.214272 -275.880068)
		(width 0.16002)
		(layer "In2.Cu")
		(net "M_B_CPU1_SA_DQS_DP<4>")
	)
	(segment
		(start 49.1109 -275.385784)
		(end 49.1109 -275.370036)
		(width 0.16002)
		(layer "In2.Cu")
		(net "M_B_CPU1_SA_DQS_DP<4>")
	)
	(segment
		(start 81.877916 -262.701786)
		(end 81.412588 -262.894572)
		(width 0.088646)
		(layer "In2.Cu")
		(net "M_B_CPU1_SA_DQS_DP<4>")
	)
	(segment
		(start 59.758072 -275.880068)
		(end 59.729878 -275.851874)
		(width 0.16002)
		(layer "In2.Cu")
		(net "M_B_CPU1_SA_DQS_DP<4>")
	)
	(segment
		(start 64.56553 -273.13255)
		(end 64.356742 -273.341338)
		(width 0.18288)
		(layer "In2.Cu")
		(net "M_B_CPU1_SA_DQS_DP<4>")
	)
	(segment
		(start 64.086994 -273.611086)
		(end 62.700662 -274.998688)
		(width 0.18288)
		(layer "In2.Cu")
		(net "M_B_CPU1_SA_DQS_DP<4>")
	)
	(segment
		(start 56.017668 -275.02739)
		(end 55.388002 -275.657056)
		(width 0.18288)
		(layer "In2.Cu")
		(net "M_B_CPU1_SA_DQS_DP<4>")
	)
	(segment
		(start 58.43143 -275.943314)
		(end 58.15965 -275.671534)
		(width 0.18288)
		(layer "In2.Cu")
		(net "M_B_CPU1_SA_DQS_DP<4>")
	)
	(segment
		(start 83.710018 -260.869684)
		(end 81.877916 -262.701786)
		(width 0.088646)
		(layer "In2.Cu")
		(net "M_B_CPU1_SA_DQS_DP<4>")
	)
	(segment
		(start 62.700662 -274.998688)
		(end 62.47638 -275.539708)
		(width 0.18288)
		(layer "In2.Cu")
		(net "M_B_CPU1_SA_DQS_DP<4>")
	)
	(segment
		(start 79.057754 -263.014206)
		(end 77.713078 -264.358882)
		(width 0.18288)
		(layer "In2.Cu")
		(net "M_B_CPU1_SA_DQS_DP<4>")
	)
	(segment
		(start 52.214272 -275.880068)
		(end 52.186078 -275.851874)
		(width 0.16002)
		(layer "In2.Cu")
		(net "M_B_CPU1_SA_DQS_DP<4>")
	)
	(segment
		(start 48.910748 -275.169884)
		(end 48.895 -275.169884)
		(width 0.16002)
		(layer "In2.Cu")
		(net "M_B_CPU1_SA_DQS_DP<4>")
	)
	(segment
		(start 54.620414 -275.851874)
		(end 54.59222 -275.880068)
		(width 0.16002)
		(layer "In2.Cu")
		(net "M_B_CPU1_SA_DQS_DP<4>")
	)
	(segment
		(start 88.23579 -260.804914)
		(end 88.225376 -260.804406)
		(width 0.088646)
		(layer "In2.Cu")
		(net "M_B_CPU1_SA_DQS_DP<4>")
	)
	(segment
		(start 54.167278 -276.30501)
		(end 52.639214 -276.30501)
		(width 0.18288)
		(layer "In2.Cu")
		(net "M_B_CPU1_SA_DQS_DP<4>")
	)
	(segment
		(start 81.1657 -262.894572)
		(end 81.046066 -263.014206)
		(width 0.088646)
		(layer "In2.Cu")
		(net "M_B_CPU1_SA_DQS_DP<4>")
	)
	(segment
		(start 65.894966 -273.54276)
		(end 65.894966 -273.526504)
		(width 0.16002)
		(layer "In2.Cu")
		(net "M_B_CPU1_SA_DQS_DP<4>")
	)
	(segment
		(start 60.002166 -276.124162)
		(end 59.973972 -276.095968)
		(width 0.16002)
		(layer "In2.Cu")
		(net "M_B_CPU1_SA_DQS_DP<4>")
	)
	(segment
		(start 77.713078 -264.358882)
		(end 74.850498 -265.5443)
		(width 0.18288)
		(layer "In2.Cu")
		(net "M_B_CPU1_SA_DQS_DP<4>")
	)
	(segment
		(start 56.454548 -275.154644)
		(end 56.4388 -275.154644)
		(width 0.16002)
		(layer "In2.Cu")
		(net "M_B_CPU1_SA_DQS_DP<4>")
	)
	(segment
		(start 87.0331 -260.92023)
		(end 87.032592 -260.920484)
		(width 0.088646)
		(layer "In2.Cu")
		(net "M_B_CPU1_SA_DQS_DP<4>")
	)
	(segment
		(start 49.388014 -275.662898)
		(end 49.139094 -275.413978)
		(width 0.18288)
		(layer "In2.Cu")
		(net "M_B_CPU1_SA_DQS_DP<4>")
	)
	(segment
		(start 65.650872 -273.298666)
		(end 65.484756 -273.13255)
		(width 0.18288)
		(layer "In2.Cu")
		(net "M_B_CPU1_SA_DQS_DP<4>")
	)
	(segment
		(start 59.973972 -276.095968)
		(end 59.973972 -276.08022)
		(width 0.16002)
		(layer "In2.Cu")
		(net "M_B_CPU1_SA_DQS_DP<4>")
	)
	(segment
		(start 54.348126 -276.124162)
		(end 54.167278 -276.30501)
		(width 0.18288)
		(layer "In2.Cu")
		(net "M_B_CPU1_SA_DQS_DP<4>")
	)
	(segment
		(start 59.549538 -275.671534)
		(end 59.056778 -275.671534)
		(width 0.18288)
		(layer "In2.Cu")
		(net "M_B_CPU1_SA_DQS_DP<4>")
	)
	(segment
		(start 55.388002 -275.657056)
		(end 54.815232 -275.657056)
		(width 0.18288)
		(layer "In2.Cu")
		(net "M_B_CPU1_SA_DQS_DP<4>")
	)
	(segment
		(start 64.115188 -273.582892)
		(end 64.086994 -273.611086)
		(width 0.16002)
		(layer "In2.Cu")
		(net "M_B_CPU1_SA_DQS_DP<4>")
	)
	(segment
		(start 88.224868 -260.804914)
		(end 88.02751 -260.804914)
		(width 0.088646)
		(layer "In2.Cu")
		(net "M_B_CPU1_SA_DQS_DP<4>")
	)
	(segment
		(start 65.894966 -273.526504)
		(end 65.695322 -273.32686)
		(width 0.16002)
		(layer "In2.Cu")
		(net "M_B_CPU1_SA_DQS_DP<4>")
	)
	(segment
		(start 52.430172 -276.095968)
		(end 52.430172 -276.08022)
		(width 0.16002)
		(layer "In2.Cu")
		(net "M_B_CPU1_SA_DQS_DP<4>")
	)
	(segment
		(start 66.099436 -273.74723)
		(end 65.92316 -273.570954)
		(width 0.18288)
		(layer "In2.Cu")
		(net "M_B_CPU1_SA_DQS_DP<4>")
	)
	(segment
		(start 47.845726 -275.29409)
		(end 47.18685 -275.29409)
		(width 0.18288)
		(layer "In2.Cu")
		(net "M_B_CPU1_SA_DQS_DP<4>")
	)
	(segment
		(start 61.92012 -276.08022)
		(end 61.92012 -276.095968)
		(width 0.16002)
		(layer "In2.Cu")
		(net "M_B_CPU1_SA_DQS_DP<4>")
	)
	(segment
		(start 54.576472 -275.880068)
		(end 54.37632 -276.08022)
		(width 0.16002)
		(layer "In2.Cu")
		(net "M_B_CPU1_SA_DQS_DP<4>")
	)
	(segment
		(start 54.37632 -276.095968)
		(end 54.348126 -276.124162)
		(width 0.16002)
		(layer "In2.Cu")
		(net "M_B_CPU1_SA_DQS_DP<4>")
	)
	(segment
		(start 74.850498 -265.5443)
		(end 66.647314 -273.74723)
		(width 0.18288)
		(layer "In2.Cu")
		(net "M_B_CPU1_SA_DQS_DP<4>")
	)
	(segment
		(start 59.056778 -275.671534)
		(end 58.784998 -275.943314)
		(width 0.18288)
		(layer "In2.Cu")
		(net "M_B_CPU1_SA_DQS_DP<4>")
	)
	(segment
		(start 52.458366 -276.124162)
		(end 52.430172 -276.095968)
		(width 0.16002)
		(layer "In2.Cu")
		(net "M_B_CPU1_SA_DQS_DP<4>")
	)
	(segment
		(start 51.993292 -275.659088)
		(end 51.54168 -275.659088)
		(width 0.18288)
		(layer "In2.Cu")
		(net "M_B_CPU1_SA_DQS_DP<4>")
	)
	(segment
		(start 65.679066 -273.32686)
		(end 65.650872 -273.298666)
		(width 0.16002)
		(layer "In2.Cu")
		(net "M_B_CPU1_SA_DQS_DP<4>")
	)
	(segment
		(start 49.1109 -275.370036)
		(end 48.910748 -275.169884)
		(width 0.16002)
		(layer "In2.Cu")
		(net "M_B_CPU1_SA_DQS_DP<4>")
	)
	(segment
		(start 58.15965 -275.671534)
		(end 56.95569 -275.671534)
		(width 0.18288)
		(layer "In2.Cu")
		(net "M_B_CPU1_SA_DQS_DP<4>")
	)
	(segment
		(start 81.412588 -262.894572)
		(end 81.1657 -262.894572)
		(width 0.088646)
		(layer "In2.Cu")
		(net "M_B_CPU1_SA_DQS_DP<4>")
	)
	(segment
		(start 59.729878 -275.851874)
		(end 59.549538 -275.671534)
		(width 0.18288)
		(layer "In2.Cu")
		(net "M_B_CPU1_SA_DQS_DP<4>")
	)
	(segment
		(start 62.164214 -275.851874)
		(end 62.13602 -275.880068)
		(width 0.16002)
		(layer "In2.Cu")
		(net "M_B_CPU1_SA_DQS_DP<4>")
	)
	(segment
		(start 61.686186 -276.329902)
		(end 60.207906 -276.329902)
		(width 0.18288)
		(layer "In2.Cu")
		(net "M_B_CPU1_SA_DQS_DP<4>")
	)
	(segment
		(start 48.173386 -274.96643)
		(end 47.845726 -275.29409)
		(width 0.18288)
		(layer "In2.Cu")
		(net "M_B_CPU1_SA_DQS_DP<4>")
	)
	(segment
		(start 59.973972 -276.08022)
		(end 59.77382 -275.880068)
		(width 0.16002)
		(layer "In2.Cu")
		(net "M_B_CPU1_SA_DQS_DP<4>")
	)
	(segment
		(start 56.682894 -275.398738)
		(end 56.6547 -275.370544)
		(width 0.16002)
		(layer "In2.Cu")
		(net "M_B_CPU1_SA_DQS_DP<4>")
	)
	(segment
		(start 56.410606 -275.12645)
		(end 56.311546 -275.02739)
		(width 0.18288)
		(layer "In2.Cu")
		(net "M_B_CPU1_SA_DQS_DP<4>")
	)
	(arc
		(start 86.092792 -260.920484)
		(mid 85.905594 -260.870341)
		(end 85.718396 -260.920484)
		(width 0.088646)
		(layer "In2.Cu")
		(net "M_B_CPU1_SA_DQS_DP<4>")
	)
	(arc
		(start 88.442292 -260.755384)
		(mid 88.342625 -260.795085)
		(end 88.23579 -260.804914)
		(width 0.088646)
		(layer "In2.Cu")
		(net "M_B_CPU1_SA_DQS_DP<4>")
	)
	(arc
		(start 84.778596 -260.920484)
		(mid 84.495894 -260.996226)
		(end 84.213192 -260.920484)
		(width 0.088646)
		(layer "In2.Cu")
		(net "M_B_CPU1_SA_DQS_DP<4>")
	)
	(arc
		(start 87.597488 -260.92023)
		(mid 87.315294 -260.995786)
		(end 87.0331 -260.92023)
		(width 0.088646)
		(layer "In2.Cu")
		(net "M_B_CPU1_SA_DQS_DP<4>")
	)
	(arc
		(start 86.658196 -260.920484)
		(mid 86.375494 -260.996226)
		(end 86.092792 -260.920484)
		(width 0.088646)
		(layer "In2.Cu")
		(net "M_B_CPU1_SA_DQS_DP<4>")
	)
	(arc
		(start 85.718396 -260.920484)
		(mid 85.435694 -260.996226)
		(end 85.152992 -260.920484)
		(width 0.088646)
		(layer "In2.Cu")
		(net "M_B_CPU1_SA_DQS_DP<4>")
	)
	(arc
		(start 87.032592 -260.920484)
		(mid 86.845394 -260.870341)
		(end 86.658196 -260.920484)
		(width 0.088646)
		(layer "In2.Cu")
		(net "M_B_CPU1_SA_DQS_DP<4>")
	)
	(arc
		(start 85.152992 -260.920484)
		(mid 84.965794 -260.870341)
		(end 84.778596 -260.920484)
		(width 0.088646)
		(layer "In2.Cu")
		(net "M_B_CPU1_SA_DQS_DP<4>")
	)
	(arc
		(start 88.02751 -260.804914)
		(mid 87.804896 -260.834233)
		(end 87.597488 -260.92023)
		(width 0.088646)
		(layer "In2.Cu")
		(net "M_B_CPU1_SA_DQS_DP<4>")
	)
	(arc
		(start 84.213192 -260.920484)
		(mid 84.122931 -260.882787)
		(end 84.025994 -260.869684)
		(width 0.088646)
		(layer "In2.Cu")
		(net "M_B_CPU1_SA_DQS_DP<4>")
	)
	(arc
		(start 88.536018 -260.712204)
		(mid 88.488165 -260.731645)
		(end 88.442292 -260.755384)
		(width 0.088646)
		(layer "In2.Cu")
		(net "M_B_CPU1_SA_DQS_DP<4>")
	)
	(segment
		(start 40.802814 -285.030672)
		(end 40.175688 -285.030672)
		(width 0.20066)
		(layer "F.Cu")
		(net "M_B_CPU1_SA_DQS_DP<3>")
	)
	(segment
		(start 45.049694 -284.605476)
		(end 44.780962 -284.605476)
		(width 0.20066)
		(layer "F.Cu")
		(net "M_B_CPU1_SA_DQS_DP<3>")
	)
	(segment
		(start 43.768772 -285.291784)
		(end 43.616626 -285.291784)
		(width 0.20066)
		(layer "F.Cu")
		(net "M_B_CPU1_SA_DQS_DP<3>")
	)
	(segment
		(start 41.073324 -285.301182)
		(end 40.802814 -285.030672)
		(width 0.20066)
		(layer "F.Cu")
		(net "M_B_CPU1_SA_DQS_DP<3>")
	)
	(segment
		(start 45.859446 -284.866588)
		(end 45.310806 -284.866588)
		(width 0.20066)
		(layer "F.Cu")
		(net "M_B_CPU1_SA_DQS_DP<3>")
	)
	(segment
		(start 45.310806 -284.866588)
		(end 45.049694 -284.605476)
		(width 0.20066)
		(layer "F.Cu")
		(net "M_B_CPU1_SA_DQS_DP<3>")
	)
	(segment
		(start 41.300908 -285.291784)
		(end 41.29151 -285.301182)
		(width 0.101854)
		(layer "F.Cu")
		(net "M_B_CPU1_SA_DQS_DP<3>")
	)
	(segment
		(start 39.11473 -284.605476)
		(end 38.853618 -284.866588)
		(width 0.20066)
		(layer "F.Cu")
		(net "M_B_CPU1_SA_DQS_DP<3>")
	)
	(segment
		(start 41.29151 -285.301182)
		(end 41.073324 -285.301182)
		(width 0.20066)
		(layer "F.Cu")
		(net "M_B_CPU1_SA_DQS_DP<3>")
	)
	(segment
		(start 92.484448 -262.336534)
		(end 92.484448 -262.87222)
		(width 0.20066)
		(layer "F.Cu")
		(net "M_B_CPU1_SA_DQS_DP<3>")
	)
	(segment
		(start 43.616626 -285.291784)
		(end 43.293284 -285.291784)
		(width 0.101854)
		(layer "F.Cu")
		(net "M_B_CPU1_SA_DQS_DP<3>")
	)
	(segment
		(start 46.964346 -284.866588)
		(end 45.859446 -284.866588)
		(width 0.20066)
		(layer "F.Cu")
		(net "M_B_CPU1_SA_DQS_DP<3>")
	)
	(segment
		(start 44.029884 -285.030672)
		(end 43.768772 -285.291784)
		(width 0.20066)
		(layer "F.Cu")
		(net "M_B_CPU1_SA_DQS_DP<3>")
	)
	(segment
		(start 40.175688 -285.030672)
		(end 39.539672 -284.605476)
		(width 0.20066)
		(layer "F.Cu")
		(net "M_B_CPU1_SA_DQS_DP<3>")
	)
	(segment
		(start 38.853618 -284.866588)
		(end 38.315646 -284.866588)
		(width 0.20066)
		(layer "F.Cu")
		(net "M_B_CPU1_SA_DQS_DP<3>")
	)
	(segment
		(start 41.53789 -285.291784)
		(end 41.300908 -285.291784)
		(width 0.101854)
		(layer "F.Cu")
		(net "M_B_CPU1_SA_DQS_DP<3>")
	)
	(segment
		(start 43.293284 -285.291784)
		(end 41.53789 -285.291784)
		(width 0.1016)
		(layer "F.Cu")
		(net "M_B_CPU1_SA_DQS_DP<3>")
	)
	(segment
		(start 92.484448 -262.87222)
		(end 92.484194 -262.872474)
		(width 0.20066)
		(layer "F.Cu")
		(net "M_B_CPU1_SA_DQS_DP<3>")
	)
	(segment
		(start 39.539672 -284.605476)
		(end 39.11473 -284.605476)
		(width 0.20066)
		(layer "F.Cu")
		(net "M_B_CPU1_SA_DQS_DP<3>")
	)
	(segment
		(start 44.355766 -285.030672)
		(end 44.029884 -285.030672)
		(width 0.20066)
		(layer "F.Cu")
		(net "M_B_CPU1_SA_DQS_DP<3>")
	)
	(segment
		(start 44.780962 -284.605476)
		(end 44.355766 -285.030672)
		(width 0.20066)
		(layer "F.Cu")
		(net "M_B_CPU1_SA_DQS_DP<3>")
	)
	(segment
		(start 79.926942 -263.57834)
		(end 78.385924 -264.21715)
		(width 0.18288)
		(layer "In4.Cu")
		(net "M_B_CPU1_SA_DQS_DP<3>")
	)
	(segment
		(start 64.90208 -277.352252)
		(end 64.49314 -277.761192)
		(width 0.18288)
		(layer "In4.Cu")
		(net "M_B_CPU1_SA_DQS_DP<3>")
	)
	(segment
		(start 91.096592 -263.241536)
		(end 90.873072 -263.370314)
		(width 0.088646)
		(layer "In4.Cu")
		(net "M_B_CPU1_SA_DQS_DP<3>")
	)
	(segment
		(start 63.506858 -278.420322)
		(end 62.027816 -279.033224)
		(width 0.18288)
		(layer "In4.Cu")
		(net "M_B_CPU1_SA_DQS_DP<3>")
	)
	(segment
		(start 56.515254 -281.57043)
		(end 56.06288 -282.022804)
		(width 0.18288)
		(layer "In4.Cu")
		(net "M_B_CPU1_SA_DQS_DP<3>")
	)
	(segment
		(start 64.49314 -277.761192)
		(end 63.506858 -278.420322)
		(width 0.18288)
		(layer "In4.Cu")
		(net "M_B_CPU1_SA_DQS_DP<3>")
	)
	(segment
		(start 91.452192 -263.241536)
		(end 91.096592 -263.241536)
		(width 0.088646)
		(layer "In4.Cu")
		(net "M_B_CPU1_SA_DQS_DP<3>")
	)
	(segment
		(start 51.237896 -285.292038)
		(end 50.870612 -285.292038)
		(width 0.18288)
		(layer "In4.Cu")
		(net "M_B_CPU1_SA_DQS_DP<3>")
	)
	(segment
		(start 55.372254 -283.389324)
		(end 54.917848 -283.84373)
		(width 0.18288)
		(layer "In4.Cu")
		(net "M_B_CPU1_SA_DQS_DP<3>")
	)
	(segment
		(start 82.883502 -263.518396)
		(end 82.823558 -263.57834)
		(width 0.088646)
		(layer "In4.Cu")
		(net "M_B_CPU1_SA_DQS_DP<3>")
	)
	(segment
		(start 60.361068 -280.699972)
		(end 58.25998 -281.57043)
		(width 0.18288)
		(layer "In4.Cu")
		(net "M_B_CPU1_SA_DQS_DP<3>")
	)
	(segment
		(start 47.8917 -284.58541)
		(end 47.245524 -284.58541)
		(width 0.18288)
		(layer "In4.Cu")
		(net "M_B_CPU1_SA_DQS_DP<3>")
	)
	(segment
		(start 91.457018 -263.238996)
		(end 91.452192 -263.241536)
		(width 0.088646)
		(layer "In4.Cu")
		(net "M_B_CPU1_SA_DQS_DP<3>")
	)
	(segment
		(start 58.25998 -281.57043)
		(end 56.515254 -281.57043)
		(width 0.18288)
		(layer "In4.Cu")
		(net "M_B_CPU1_SA_DQS_DP<3>")
	)
	(segment
		(start 49.56429 -284.40253)
		(end 48.07458 -284.40253)
		(width 0.18288)
		(layer "In4.Cu")
		(net "M_B_CPU1_SA_DQS_DP<3>")
	)
	(segment
		(start 83.65109 -263.337294)
		(end 83.408266 -263.337294)
		(width 0.088646)
		(layer "In4.Cu")
		(net "M_B_CPU1_SA_DQS_DP<3>")
	)
	(segment
		(start 83.227164 -263.518396)
		(end 82.883502 -263.518396)
		(width 0.088646)
		(layer "In4.Cu")
		(net "M_B_CPU1_SA_DQS_DP<3>")
	)
	(segment
		(start 47.245524 -284.58541)
		(end 46.964346 -284.866588)
		(width 0.18288)
		(layer "In4.Cu")
		(net "M_B_CPU1_SA_DQS_DP<3>")
	)
	(segment
		(start 65.941448 -275.0947)
		(end 65.749678 -275.306536)
		(width 0.18288)
		(layer "In4.Cu")
		(net "M_B_CPU1_SA_DQS_DP<3>")
	)
	(segment
		(start 68.61429 -273.98853)
		(end 65.941448 -275.0947)
		(width 0.18288)
		(layer "In4.Cu")
		(net "M_B_CPU1_SA_DQS_DP<3>")
	)
	(segment
		(start 82.783934 -263.57834)
		(end 79.926942 -263.57834)
		(width 0.18288)
		(layer "In4.Cu")
		(net "M_B_CPU1_SA_DQS_DP<3>")
	)
	(segment
		(start 55.734966 -282.513532)
		(end 55.372254 -283.389324)
		(width 0.18288)
		(layer "In4.Cu")
		(net "M_B_CPU1_SA_DQS_DP<3>")
	)
	(segment
		(start 52.656232 -284.780482)
		(end 52.071524 -284.780482)
		(width 0.18288)
		(layer "In4.Cu")
		(net "M_B_CPU1_SA_DQS_DP<3>")
	)
	(segment
		(start 50.870612 -285.292038)
		(end 50.60315 -285.024576)
		(width 0.18288)
		(layer "In4.Cu")
		(net "M_B_CPU1_SA_DQS_DP<3>")
	)
	(segment
		(start 91.514168 -263.245854)
		(end 91.457018 -263.238996)
		(width 0.088646)
		(layer "In4.Cu")
		(net "M_B_CPU1_SA_DQS_DP<3>")
	)
	(segment
		(start 92.143834 -262.96239)
		(end 91.718638 -263.204198)
		(width 0.088646)
		(layer "In4.Cu")
		(net "M_B_CPU1_SA_DQS_DP<3>")
	)
	(segment
		(start 82.823558 -263.57834)
		(end 82.783934 -263.57834)
		(width 0.088646)
		(layer "In4.Cu")
		(net "M_B_CPU1_SA_DQS_DP<3>")
	)
	(segment
		(start 54.917848 -283.84373)
		(end 52.656232 -284.780482)
		(width 0.18288)
		(layer "In4.Cu")
		(net "M_B_CPU1_SA_DQS_DP<3>")
	)
	(segment
		(start 56.06288 -282.022804)
		(end 55.734966 -282.513532)
		(width 0.18288)
		(layer "In4.Cu")
		(net "M_B_CPU1_SA_DQS_DP<3>")
	)
	(segment
		(start 50.186336 -285.024576)
		(end 49.56429 -284.40253)
		(width 0.18288)
		(layer "In4.Cu")
		(net "M_B_CPU1_SA_DQS_DP<3>")
	)
	(segment
		(start 62.027816 -279.033224)
		(end 60.361068 -280.699972)
		(width 0.18288)
		(layer "In4.Cu")
		(net "M_B_CPU1_SA_DQS_DP<3>")
	)
	(segment
		(start 50.60315 -285.024576)
		(end 50.186336 -285.024576)
		(width 0.18288)
		(layer "In4.Cu")
		(net "M_B_CPU1_SA_DQS_DP<3>")
	)
	(segment
		(start 52.071524 -284.780482)
		(end 51.522122 -285.007812)
		(width 0.18288)
		(layer "In4.Cu")
		(net "M_B_CPU1_SA_DQS_DP<3>")
	)
	(segment
		(start 90.321892 -263.361932)
		(end 90.321892 -263.362186)
		(width 0.088646)
		(layer "In4.Cu")
		(net "M_B_CPU1_SA_DQS_DP<3>")
	)
	(segment
		(start 51.522122 -285.007812)
		(end 51.237896 -285.292038)
		(width 0.18288)
		(layer "In4.Cu")
		(net "M_B_CPU1_SA_DQS_DP<3>")
	)
	(segment
		(start 83.408266 -263.337294)
		(end 83.227164 -263.518396)
		(width 0.088646)
		(layer "In4.Cu")
		(net "M_B_CPU1_SA_DQS_DP<3>")
	)
	(segment
		(start 78.385924 -264.21715)
		(end 68.61429 -273.98853)
		(width 0.18288)
		(layer "In4.Cu")
		(net "M_B_CPU1_SA_DQS_DP<3>")
	)
	(segment
		(start 65.749678 -275.306536)
		(end 64.90208 -277.352252)
		(width 0.18288)
		(layer "In4.Cu")
		(net "M_B_CPU1_SA_DQS_DP<3>")
	)
	(segment
		(start 48.07458 -284.40253)
		(end 47.8917 -284.58541)
		(width 0.18288)
		(layer "In4.Cu")
		(net "M_B_CPU1_SA_DQS_DP<3>")
	)
	(arc
		(start 90.321892 -263.362186)
		(mid 90.134694 -263.312043)
		(end 89.947496 -263.362186)
		(width 0.088646)
		(layer "In4.Cu")
		(net "M_B_CPU1_SA_DQS_DP<3>")
	)
	(arc
		(start 91.718638 -263.204198)
		(mid 91.619796 -263.241708)
		(end 91.514168 -263.245854)
		(width 0.088646)
		(layer "In4.Cu")
		(net "M_B_CPU1_SA_DQS_DP<3>")
	)
	(arc
		(start 86.562692 -263.362186)
		(mid 86.375494 -263.312043)
		(end 86.188296 -263.362186)
		(width 0.088646)
		(layer "In4.Cu")
		(net "M_B_CPU1_SA_DQS_DP<3>")
	)
	(arc
		(start 87.502492 -263.362186)
		(mid 87.315294 -263.312043)
		(end 87.128096 -263.362186)
		(width 0.088646)
		(layer "In4.Cu")
		(net "M_B_CPU1_SA_DQS_DP<3>")
	)
	(arc
		(start 89.947496 -263.362186)
		(mid 89.664794 -263.437928)
		(end 89.382092 -263.362186)
		(width 0.088646)
		(layer "In4.Cu")
		(net "M_B_CPU1_SA_DQS_DP<3>")
	)
	(arc
		(start 85.622892 -263.362186)
		(mid 85.435694 -263.312043)
		(end 85.248496 -263.362186)
		(width 0.088646)
		(layer "In4.Cu")
		(net "M_B_CPU1_SA_DQS_DP<3>")
	)
	(arc
		(start 88.442292 -263.362186)
		(mid 88.255094 -263.312043)
		(end 88.067896 -263.362186)
		(width 0.088646)
		(layer "In4.Cu")
		(net "M_B_CPU1_SA_DQS_DP<3>")
	)
	(arc
		(start 84.308696 -263.362186)
		(mid 84.025994 -263.437928)
		(end 83.743292 -263.362186)
		(width 0.088646)
		(layer "In4.Cu")
		(net "M_B_CPU1_SA_DQS_DP<3>")
	)
	(arc
		(start 84.683092 -263.362186)
		(mid 84.495894 -263.312043)
		(end 84.308696 -263.362186)
		(width 0.088646)
		(layer "In4.Cu")
		(net "M_B_CPU1_SA_DQS_DP<3>")
	)
	(arc
		(start 83.743292 -263.362186)
		(mid 83.698834 -263.34367)
		(end 83.65109 -263.337294)
		(width 0.088646)
		(layer "In4.Cu")
		(net "M_B_CPU1_SA_DQS_DP<3>")
	)
	(arc
		(start 90.873072 -263.370314)
		(mid 90.596407 -263.437785)
		(end 90.321892 -263.361932)
		(width 0.088646)
		(layer "In4.Cu")
		(net "M_B_CPU1_SA_DQS_DP<3>")
	)
	(arc
		(start 92.484194 -262.872474)
		(mid 92.308173 -262.895311)
		(end 92.143834 -262.96239)
		(width 0.088646)
		(layer "In4.Cu")
		(net "M_B_CPU1_SA_DQS_DP<3>")
	)
	(arc
		(start 86.188296 -263.362186)
		(mid 85.905594 -263.437928)
		(end 85.622892 -263.362186)
		(width 0.088646)
		(layer "In4.Cu")
		(net "M_B_CPU1_SA_DQS_DP<3>")
	)
	(arc
		(start 87.128096 -263.362186)
		(mid 86.845394 -263.437928)
		(end 86.562692 -263.362186)
		(width 0.088646)
		(layer "In4.Cu")
		(net "M_B_CPU1_SA_DQS_DP<3>")
	)
	(arc
		(start 85.248496 -263.362186)
		(mid 84.965794 -263.437928)
		(end 84.683092 -263.362186)
		(width 0.088646)
		(layer "In4.Cu")
		(net "M_B_CPU1_SA_DQS_DP<3>")
	)
	(arc
		(start 89.007696 -263.362186)
		(mid 88.724994 -263.437928)
		(end 88.442292 -263.362186)
		(width 0.088646)
		(layer "In4.Cu")
		(net "M_B_CPU1_SA_DQS_DP<3>")
	)
	(arc
		(start 89.382092 -263.362186)
		(mid 89.194894 -263.312043)
		(end 89.007696 -263.362186)
		(width 0.088646)
		(layer "In4.Cu")
		(net "M_B_CPU1_SA_DQS_DP<3>")
	)
	(arc
		(start 88.067896 -263.362186)
		(mid 87.785194 -263.437928)
		(end 87.502492 -263.362186)
		(width 0.088646)
		(layer "In4.Cu")
		(net "M_B_CPU1_SA_DQS_DP<3>")
	)
	(segment
		(start 43.293284 -294.641778)
		(end 41.53789 -294.641778)
		(width 0.1016)
		(layer "F.Cu")
		(net "M_B_CPU1_SA_DQS_DP<2>")
	)
	(segment
		(start 89.194894 -264.778236)
		(end 89.194894 -265.314176)
		(width 0.20066)
		(layer "F.Cu")
		(net "M_B_CPU1_SA_DQS_DP<2>")
	)
	(segment
		(start 44.355766 -294.380666)
		(end 44.029884 -294.380666)
		(width 0.20066)
		(layer "F.Cu")
		(net "M_B_CPU1_SA_DQS_DP<2>")
	)
	(segment
		(start 40.175688 -294.380666)
		(end 39.539672 -293.95547)
		(width 0.20066)
		(layer "F.Cu")
		(net "M_B_CPU1_SA_DQS_DP<2>")
	)
	(segment
		(start 39.539672 -293.95547)
		(end 39.11473 -293.95547)
		(width 0.20066)
		(layer "F.Cu")
		(net "M_B_CPU1_SA_DQS_DP<2>")
	)
	(segment
		(start 41.29151 -294.651176)
		(end 41.073324 -294.651176)
		(width 0.20066)
		(layer "F.Cu")
		(net "M_B_CPU1_SA_DQS_DP<2>")
	)
	(segment
		(start 41.53789 -294.641778)
		(end 41.300908 -294.641778)
		(width 0.101854)
		(layer "F.Cu")
		(net "M_B_CPU1_SA_DQS_DP<2>")
	)
	(segment
		(start 41.300908 -294.641778)
		(end 41.29151 -294.651176)
		(width 0.101854)
		(layer "F.Cu")
		(net "M_B_CPU1_SA_DQS_DP<2>")
	)
	(segment
		(start 46.964346 -294.216582)
		(end 45.859446 -294.216582)
		(width 0.20066)
		(layer "F.Cu")
		(net "M_B_CPU1_SA_DQS_DP<2>")
	)
	(segment
		(start 45.310806 -294.216582)
		(end 45.049694 -293.95547)
		(width 0.20066)
		(layer "F.Cu")
		(net "M_B_CPU1_SA_DQS_DP<2>")
	)
	(segment
		(start 41.073324 -294.651176)
		(end 40.802814 -294.380666)
		(width 0.20066)
		(layer "F.Cu")
		(net "M_B_CPU1_SA_DQS_DP<2>")
	)
	(segment
		(start 43.616626 -294.641778)
		(end 43.293284 -294.641778)
		(width 0.101854)
		(layer "F.Cu")
		(net "M_B_CPU1_SA_DQS_DP<2>")
	)
	(segment
		(start 44.029884 -294.380666)
		(end 43.768772 -294.641778)
		(width 0.20066)
		(layer "F.Cu")
		(net "M_B_CPU1_SA_DQS_DP<2>")
	)
	(segment
		(start 38.853618 -294.216582)
		(end 38.315646 -294.216582)
		(width 0.20066)
		(layer "F.Cu")
		(net "M_B_CPU1_SA_DQS_DP<2>")
	)
	(segment
		(start 45.859446 -294.216582)
		(end 45.310806 -294.216582)
		(width 0.20066)
		(layer "F.Cu")
		(net "M_B_CPU1_SA_DQS_DP<2>")
	)
	(segment
		(start 43.768772 -294.641778)
		(end 43.616626 -294.641778)
		(width 0.20066)
		(layer "F.Cu")
		(net "M_B_CPU1_SA_DQS_DP<2>")
	)
	(segment
		(start 40.802814 -294.380666)
		(end 40.175688 -294.380666)
		(width 0.20066)
		(layer "F.Cu")
		(net "M_B_CPU1_SA_DQS_DP<2>")
	)
	(segment
		(start 45.049694 -293.95547)
		(end 44.780962 -293.95547)
		(width 0.20066)
		(layer "F.Cu")
		(net "M_B_CPU1_SA_DQS_DP<2>")
	)
	(segment
		(start 44.780962 -293.95547)
		(end 44.355766 -294.380666)
		(width 0.20066)
		(layer "F.Cu")
		(net "M_B_CPU1_SA_DQS_DP<2>")
	)
	(segment
		(start 39.11473 -293.95547)
		(end 38.853618 -294.216582)
		(width 0.20066)
		(layer "F.Cu")
		(net "M_B_CPU1_SA_DQS_DP<2>")
	)
	(segment
		(start 54.59222 -294.580056)
		(end 54.576472 -294.580056)
		(width 0.16002)
		(layer "In2.Cu")
		(net "M_B_CPU1_SA_DQS_DP<2>")
	)
	(segment
		(start 60.081414 -288.004504)
		(end 60.081414 -288.02076)
		(width 0.16002)
		(layer "In2.Cu")
		(net "M_B_CPU1_SA_DQS_DP<2>")
	)
	(segment
		(start 66.219324 -284.412182)
		(end 66.19113 -284.440376)
		(width 0.16002)
		(layer "In2.Cu")
		(net "M_B_CPU1_SA_DQS_DP<2>")
	)
	(segment
		(start 83.686396 -266.034774)
		(end 82.68208 -267.03909)
		(width 0.088646)
		(layer "In2.Cu")
		(net "M_B_CPU1_SA_DQS_DP<2>")
	)
	(segment
		(start 56.985154 -291.92093)
		(end 56.777636 -292.128448)
		(width 0.18288)
		(layer "In2.Cu")
		(net "M_B_CPU1_SA_DQS_DP<2>")
	)
	(segment
		(start 52.186078 -294.551862)
		(end 52.001928 -294.367712)
		(width 0.18288)
		(layer "In2.Cu")
		(net "M_B_CPU1_SA_DQS_DP<2>")
	)
	(segment
		(start 49.139094 -294.113966)
		(end 49.1109 -294.085772)
		(width 0.16002)
		(layer "In2.Cu")
		(net "M_B_CPU1_SA_DQS_DP<2>")
	)
	(segment
		(start 59.17438 -290.64712)
		(end 59.145424 -290.716462)
		(width 0.18288)
		(layer "In2.Cu")
		(net "M_B_CPU1_SA_DQS_DP<2>")
	)
	(segment
		(start 62.091062 -286.990282)
		(end 62.075314 -286.990282)
		(width 0.16002)
		(layer "In2.Cu")
		(net "M_B_CPU1_SA_DQS_DP<2>")
	)
	(segment
		(start 48.895 -293.869872)
		(end 48.866806 -293.841678)
		(width 0.16002)
		(layer "In2.Cu")
		(net "M_B_CPU1_SA_DQS_DP<2>")
	)
	(segment
		(start 50.837338 -294.641524)
		(end 50.57013 -294.374316)
		(width 0.18288)
		(layer "In2.Cu")
		(net "M_B_CPU1_SA_DQS_DP<2>")
	)
	(segment
		(start 64.366394 -285.268162)
		(end 64.3382 -285.296356)
		(width 0.16002)
		(layer "In2.Cu")
		(net "M_B_CPU1_SA_DQS_DP<2>")
	)
	(segment
		(start 65.947036 -284.68447)
		(end 65.661794 -284.969712)
		(width 0.18288)
		(layer "In2.Cu")
		(net "M_B_CPU1_SA_DQS_DP<2>")
	)
	(segment
		(start 57.939178 -291.92093)
		(end 56.985154 -291.92093)
		(width 0.18288)
		(layer "In2.Cu")
		(net "M_B_CPU1_SA_DQS_DP<2>")
	)
	(segment
		(start 60.081414 -288.02076)
		(end 60.05322 -288.048954)
		(width 0.16002)
		(layer "In2.Cu")
		(net "M_B_CPU1_SA_DQS_DP<2>")
	)
	(segment
		(start 52.430172 -294.780208)
		(end 52.23002 -294.580056)
		(width 0.16002)
		(layer "In2.Cu")
		(net "M_B_CPU1_SA_DQS_DP<2>")
	)
	(segment
		(start 64.1223 -285.496)
		(end 64.1223 -285.512256)
		(width 0.16002)
		(layer "In2.Cu")
		(net "M_B_CPU1_SA_DQS_DP<2>")
	)
	(segment
		(start 85.1535 -265.80338)
		(end 85.152992 -265.803888)
		(width 0.088646)
		(layer "In2.Cu")
		(net "M_B_CPU1_SA_DQS_DP<2>")
	)
	(segment
		(start 61.846968 -287.234376)
		(end 61.442854 -287.63849)
		(width 0.18288)
		(layer "In2.Cu")
		(net "M_B_CPU1_SA_DQS_DP<2>")
	)
	(segment
		(start 82.68208 -267.123926)
		(end 80.71231 -269.093696)
		(width 0.18288)
		(layer "In2.Cu")
		(net "M_B_CPU1_SA_DQS_DP<2>")
	)
	(segment
		(start 56.533542 -292.372542)
		(end 56.505348 -292.400736)
		(width 0.16002)
		(layer "In2.Cu")
		(net "M_B_CPU1_SA_DQS_DP<2>")
	)
	(segment
		(start 66.19113 -284.440376)
		(end 66.175382 -284.440376)
		(width 0.16002)
		(layer "In2.Cu")
		(net "M_B_CPU1_SA_DQS_DP<2>")
	)
	(segment
		(start 56.505348 -292.400736)
		(end 55.071518 -293.834566)
		(width 0.18288)
		(layer "In2.Cu")
		(net "M_B_CPU1_SA_DQS_DP<2>")
	)
	(segment
		(start 59.09691 -290.763198)
		(end 58.608214 -291.251894)
		(width 0.18288)
		(layer "In2.Cu")
		(net "M_B_CPU1_SA_DQS_DP<2>")
	)
	(segment
		(start 47.671228 -293.958264)
		(end 47.222664 -293.958264)
		(width 0.18288)
		(layer "In2.Cu")
		(net "M_B_CPU1_SA_DQS_DP<2>")
	)
	(segment
		(start 65.661794 -284.969712)
		(end 64.664844 -284.969712)
		(width 0.18288)
		(layer "In2.Cu")
		(net "M_B_CPU1_SA_DQS_DP<2>")
	)
	(segment
		(start 49.399444 -294.374316)
		(end 49.139094 -294.113966)
		(width 0.18288)
		(layer "In2.Cu")
		(net "M_B_CPU1_SA_DQS_DP<2>")
	)
	(segment
		(start 59.36742 -288.977324)
		(end 59.36742 -290.1823)
		(width 0.18288)
		(layer "In2.Cu")
		(net "M_B_CPU1_SA_DQS_DP<2>")
	)
	(segment
		(start 66.891154 -284.10789)
		(end 66.523616 -284.10789)
		(width 0.18288)
		(layer "In2.Cu")
		(net "M_B_CPU1_SA_DQS_DP<2>")
	)
	(segment
		(start 70.729856 -278.929338)
		(end 70.729856 -280.269188)
		(width 0.18288)
		(layer "In2.Cu")
		(net "M_B_CPU1_SA_DQS_DP<2>")
	)
	(segment
		(start 58.36412 -291.48024)
		(end 58.36412 -291.495988)
		(width 0.16002)
		(layer "In2.Cu")
		(net "M_B_CPU1_SA_DQS_DP<2>")
	)
	(segment
		(start 82.68208 -267.03909)
		(end 82.68208 -267.123926)
		(width 0.088646)
		(layer "In2.Cu")
		(net "M_B_CPU1_SA_DQS_DP<2>")
	)
	(segment
		(start 65.97523 -284.656276)
		(end 65.947036 -284.68447)
		(width 0.16002)
		(layer "In2.Cu")
		(net "M_B_CPU1_SA_DQS_DP<2>")
	)
	(segment
		(start 49.1109 -294.070024)
		(end 48.910748 -293.869872)
		(width 0.16002)
		(layer "In2.Cu")
		(net "M_B_CPU1_SA_DQS_DP<2>")
	)
	(segment
		(start 58.36412 -291.495988)
		(end 58.335926 -291.524182)
		(width 0.16002)
		(layer "In2.Cu")
		(net "M_B_CPU1_SA_DQS_DP<2>")
	)
	(segment
		(start 56.749442 -292.156642)
		(end 56.733186 -292.156642)
		(width 0.16002)
		(layer "In2.Cu")
		(net "M_B_CPU1_SA_DQS_DP<2>")
	)
	(segment
		(start 62.075314 -286.990282)
		(end 61.875162 -287.190434)
		(width 0.16002)
		(layer "In2.Cu")
		(net "M_B_CPU1_SA_DQS_DP<2>")
	)
	(segment
		(start 87.0331 -265.80338)
		(end 87.032592 -265.803888)
		(width 0.088646)
		(layer "In2.Cu")
		(net "M_B_CPU1_SA_DQS_DP<2>")
	)
	(segment
		(start 48.321976 -293.68877)
		(end 47.671228 -293.958264)
		(width 0.18288)
		(layer "In2.Cu")
		(net "M_B_CPU1_SA_DQS_DP<2>")
	)
	(segment
		(start 85.718396 -265.803888)
		(end 85.717888 -265.80338)
		(width 0.088646)
		(layer "In2.Cu")
		(net "M_B_CPU1_SA_DQS_DP<2>")
	)
	(segment
		(start 66.523616 -284.10789)
		(end 66.219324 -284.412182)
		(width 0.18288)
		(layer "In2.Cu")
		(net "M_B_CPU1_SA_DQS_DP<2>")
	)
	(segment
		(start 61.442854 -287.63849)
		(end 60.463684 -287.63849)
		(width 0.18288)
		(layer "In2.Cu")
		(net "M_B_CPU1_SA_DQS_DP<2>")
	)
	(segment
		(start 56.777636 -292.128448)
		(end 56.749442 -292.156642)
		(width 0.16002)
		(layer "In2.Cu")
		(net "M_B_CPU1_SA_DQS_DP<2>")
	)
	(segment
		(start 63.255906 -286.37865)
		(end 62.702694 -286.37865)
		(width 0.18288)
		(layer "In2.Cu")
		(net "M_B_CPU1_SA_DQS_DP<2>")
	)
	(segment
		(start 70.729856 -280.269188)
		(end 66.891154 -284.10789)
		(width 0.18288)
		(layer "In2.Cu")
		(net "M_B_CPU1_SA_DQS_DP<2>")
	)
	(segment
		(start 88.817196 -265.314176)
		(end 88.536018 -265.595354)
		(width 0.088646)
		(layer "In2.Cu")
		(net "M_B_CPU1_SA_DQS_DP<2>")
	)
	(segment
		(start 52.214272 -294.580056)
		(end 52.186078 -294.551862)
		(width 0.16002)
		(layer "In2.Cu")
		(net "M_B_CPU1_SA_DQS_DP<2>")
	)
	(segment
		(start 52.664106 -295.02989)
		(end 52.458366 -294.82415)
		(width 0.18288)
		(layer "In2.Cu")
		(net "M_B_CPU1_SA_DQS_DP<2>")
	)
	(segment
		(start 62.119256 -286.962088)
		(end 62.091062 -286.990282)
		(width 0.16002)
		(layer "In2.Cu")
		(net "M_B_CPU1_SA_DQS_DP<2>")
	)
	(segment
		(start 56.733186 -292.156642)
		(end 56.533542 -292.356286)
		(width 0.16002)
		(layer "In2.Cu")
		(net "M_B_CPU1_SA_DQS_DP<2>")
	)
	(segment
		(start 60.463684 -287.63849)
		(end 60.325508 -287.776666)
		(width 0.18288)
		(layer "In2.Cu")
		(net "M_B_CPU1_SA_DQS_DP<2>")
	)
	(segment
		(start 64.1223 -285.512256)
		(end 64.094106 -285.54045)
		(width 0.16002)
		(layer "In2.Cu")
		(net "M_B_CPU1_SA_DQS_DP<2>")
	)
	(segment
		(start 47.222664 -293.958264)
		(end 46.964346 -294.216582)
		(width 0.18288)
		(layer "In2.Cu")
		(net "M_B_CPU1_SA_DQS_DP<2>")
	)
	(segment
		(start 54.348126 -294.82415)
		(end 54.142386 -295.02989)
		(width 0.18288)
		(layer "In2.Cu")
		(net "M_B_CPU1_SA_DQS_DP<2>")
	)
	(segment
		(start 80.71231 -269.093696)
		(end 80.461866 -269.197328)
		(width 0.18288)
		(layer "In2.Cu")
		(net "M_B_CPU1_SA_DQS_DP<2>")
	)
	(segment
		(start 52.001928 -294.367712)
		(end 51.592226 -294.367712)
		(width 0.18288)
		(layer "In2.Cu")
		(net "M_B_CPU1_SA_DQS_DP<2>")
	)
	(segment
		(start 84.001864 -265.861038)
		(end 83.758024 -265.982958)
		(width 0.088646)
		(layer "In2.Cu")
		(net "M_B_CPU1_SA_DQS_DP<2>")
	)
	(segment
		(start 54.37632 -294.780208)
		(end 54.37632 -294.795956)
		(width 0.16002)
		(layer "In2.Cu")
		(net "M_B_CPU1_SA_DQS_DP<2>")
	)
	(segment
		(start 65.97523 -284.640528)
		(end 65.97523 -284.656276)
		(width 0.16002)
		(layer "In2.Cu")
		(net "M_B_CPU1_SA_DQS_DP<2>")
	)
	(segment
		(start 48.713898 -293.68877)
		(end 48.321976 -293.68877)
		(width 0.18288)
		(layer "In2.Cu")
		(net "M_B_CPU1_SA_DQS_DP<2>")
	)
	(segment
		(start 52.430172 -294.795956)
		(end 52.430172 -294.780208)
		(width 0.16002)
		(layer "In2.Cu")
		(net "M_B_CPU1_SA_DQS_DP<2>")
	)
	(segment
		(start 54.620414 -294.551862)
		(end 54.59222 -294.580056)
		(width 0.16002)
		(layer "In2.Cu")
		(net "M_B_CPU1_SA_DQS_DP<2>")
	)
	(segment
		(start 54.576472 -294.580056)
		(end 54.37632 -294.780208)
		(width 0.16002)
		(layer "In2.Cu")
		(net "M_B_CPU1_SA_DQS_DP<2>")
	)
	(segment
		(start 59.539632 -288.562796)
		(end 59.36742 -288.977324)
		(width 0.18288)
		(layer "In2.Cu")
		(net "M_B_CPU1_SA_DQS_DP<2>")
	)
	(segment
		(start 66.175382 -284.440376)
		(end 65.97523 -284.640528)
		(width 0.16002)
		(layer "In2.Cu")
		(net "M_B_CPU1_SA_DQS_DP<2>")
	)
	(segment
		(start 64.664844 -284.969712)
		(end 64.366394 -285.268162)
		(width 0.18288)
		(layer "In2.Cu")
		(net "M_B_CPU1_SA_DQS_DP<2>")
	)
	(segment
		(start 52.458366 -294.82415)
		(end 52.430172 -294.795956)
		(width 0.16002)
		(layer "In2.Cu")
		(net "M_B_CPU1_SA_DQS_DP<2>")
	)
	(segment
		(start 58.608214 -291.251894)
		(end 58.58002 -291.280088)
		(width 0.16002)
		(layer "In2.Cu")
		(net "M_B_CPU1_SA_DQS_DP<2>")
	)
	(segment
		(start 58.58002 -291.280088)
		(end 58.564272 -291.280088)
		(width 0.16002)
		(layer "In2.Cu")
		(net "M_B_CPU1_SA_DQS_DP<2>")
	)
	(segment
		(start 58.335926 -291.524182)
		(end 57.939178 -291.92093)
		(width 0.18288)
		(layer "In2.Cu")
		(net "M_B_CPU1_SA_DQS_DP<2>")
	)
	(segment
		(start 60.297314 -287.80486)
		(end 60.281058 -287.80486)
		(width 0.16002)
		(layer "In2.Cu")
		(net "M_B_CPU1_SA_DQS_DP<2>")
	)
	(segment
		(start 50.57013 -294.374316)
		(end 49.399444 -294.374316)
		(width 0.18288)
		(layer "In2.Cu")
		(net "M_B_CPU1_SA_DQS_DP<2>")
	)
	(segment
		(start 54.37632 -294.795956)
		(end 54.348126 -294.82415)
		(width 0.16002)
		(layer "In2.Cu")
		(net "M_B_CPU1_SA_DQS_DP<2>")
	)
	(segment
		(start 55.071518 -294.100758)
		(end 54.620414 -294.551862)
		(width 0.18288)
		(layer "In2.Cu")
		(net "M_B_CPU1_SA_DQS_DP<2>")
	)
	(segment
		(start 80.461866 -269.197328)
		(end 70.729856 -278.929338)
		(width 0.18288)
		(layer "In2.Cu")
		(net "M_B_CPU1_SA_DQS_DP<2>")
	)
	(segment
		(start 55.071518 -293.834566)
		(end 55.071518 -294.100758)
		(width 0.18288)
		(layer "In2.Cu")
		(net "M_B_CPU1_SA_DQS_DP<2>")
	)
	(segment
		(start 54.142386 -295.02989)
		(end 52.664106 -295.02989)
		(width 0.18288)
		(layer "In2.Cu")
		(net "M_B_CPU1_SA_DQS_DP<2>")
	)
	(segment
		(start 64.321944 -285.296356)
		(end 64.1223 -285.496)
		(width 0.16002)
		(layer "In2.Cu")
		(net "M_B_CPU1_SA_DQS_DP<2>")
	)
	(segment
		(start 51.318414 -294.641524)
		(end 50.837338 -294.641524)
		(width 0.18288)
		(layer "In2.Cu")
		(net "M_B_CPU1_SA_DQS_DP<2>")
	)
	(segment
		(start 62.702694 -286.37865)
		(end 62.119256 -286.962088)
		(width 0.18288)
		(layer "In2.Cu")
		(net "M_B_CPU1_SA_DQS_DP<2>")
	)
	(segment
		(start 58.564272 -291.280088)
		(end 58.36412 -291.48024)
		(width 0.16002)
		(layer "In2.Cu")
		(net "M_B_CPU1_SA_DQS_DP<2>")
	)
	(segment
		(start 64.094106 -285.54045)
		(end 63.255906 -286.37865)
		(width 0.18288)
		(layer "In2.Cu")
		(net "M_B_CPU1_SA_DQS_DP<2>")
	)
	(segment
		(start 88.23579 -265.688064)
		(end 88.02751 -265.688064)
		(width 0.088646)
		(layer "In2.Cu")
		(net "M_B_CPU1_SA_DQS_DP<2>")
	)
	(segment
		(start 56.533542 -292.356286)
		(end 56.533542 -292.372542)
		(width 0.16002)
		(layer "In2.Cu")
		(net "M_B_CPU1_SA_DQS_DP<2>")
	)
	(segment
		(start 61.875162 -287.206182)
		(end 61.846968 -287.234376)
		(width 0.16002)
		(layer "In2.Cu")
		(net "M_B_CPU1_SA_DQS_DP<2>")
	)
	(segment
		(start 60.325508 -287.776666)
		(end 60.297314 -287.80486)
		(width 0.16002)
		(layer "In2.Cu")
		(net "M_B_CPU1_SA_DQS_DP<2>")
	)
	(segment
		(start 89.194894 -265.314176)
		(end 88.817196 -265.314176)
		(width 0.088646)
		(layer "In2.Cu")
		(net "M_B_CPU1_SA_DQS_DP<2>")
	)
	(segment
		(start 48.866806 -293.841678)
		(end 48.713898 -293.68877)
		(width 0.18288)
		(layer "In2.Cu")
		(net "M_B_CPU1_SA_DQS_DP<2>")
	)
	(segment
		(start 48.910748 -293.869872)
		(end 48.895 -293.869872)
		(width 0.16002)
		(layer "In2.Cu")
		(net "M_B_CPU1_SA_DQS_DP<2>")
	)
	(segment
		(start 61.875162 -287.190434)
		(end 61.875162 -287.206182)
		(width 0.16002)
		(layer "In2.Cu")
		(net "M_B_CPU1_SA_DQS_DP<2>")
	)
	(segment
		(start 59.174634 -290.646104)
		(end 59.17438 -290.64712)
		(width 0.18288)
		(layer "In2.Cu")
		(net "M_B_CPU1_SA_DQS_DP<2>")
	)
	(segment
		(start 49.1109 -294.085772)
		(end 49.1109 -294.070024)
		(width 0.16002)
		(layer "In2.Cu")
		(net "M_B_CPU1_SA_DQS_DP<2>")
	)
	(segment
		(start 59.145424 -290.716462)
		(end 59.09691 -290.763198)
		(width 0.18288)
		(layer "In2.Cu")
		(net "M_B_CPU1_SA_DQS_DP<2>")
	)
	(segment
		(start 64.3382 -285.296356)
		(end 64.321944 -285.296356)
		(width 0.16002)
		(layer "In2.Cu")
		(net "M_B_CPU1_SA_DQS_DP<2>")
	)
	(segment
		(start 60.281058 -287.80486)
		(end 60.081414 -288.004504)
		(width 0.16002)
		(layer "In2.Cu")
		(net "M_B_CPU1_SA_DQS_DP<2>")
	)
	(segment
		(start 52.23002 -294.580056)
		(end 52.214272 -294.580056)
		(width 0.16002)
		(layer "In2.Cu")
		(net "M_B_CPU1_SA_DQS_DP<2>")
	)
	(segment
		(start 51.592226 -294.367712)
		(end 51.318414 -294.641524)
		(width 0.18288)
		(layer "In2.Cu")
		(net "M_B_CPU1_SA_DQS_DP<2>")
	)
	(segment
		(start 60.05322 -288.048954)
		(end 59.539632 -288.562796)
		(width 0.18288)
		(layer "In2.Cu")
		(net "M_B_CPU1_SA_DQS_DP<2>")
	)
	(segment
		(start 59.36742 -290.1823)
		(end 59.174634 -290.646104)
		(width 0.18288)
		(layer "In2.Cu")
		(net "M_B_CPU1_SA_DQS_DP<2>")
	)
	(arc
		(start 88.536018 -265.595354)
		(mid 88.488165 -265.614795)
		(end 88.442292 -265.638534)
		(width 0.088646)
		(layer "In2.Cu")
		(net "M_B_CPU1_SA_DQS_DP<2>")
	)
	(arc
		(start 85.717888 -265.80338)
		(mid 85.435694 -265.878936)
		(end 85.1535 -265.80338)
		(width 0.088646)
		(layer "In2.Cu")
		(net "M_B_CPU1_SA_DQS_DP<2>")
	)
	(arc
		(start 83.758024 -265.982958)
		(mid 83.720107 -266.005962)
		(end 83.686396 -266.034774)
		(width 0.088646)
		(layer "In2.Cu")
		(net "M_B_CPU1_SA_DQS_DP<2>")
	)
	(arc
		(start 87.597488 -265.80338)
		(mid 87.315294 -265.878936)
		(end 87.0331 -265.80338)
		(width 0.088646)
		(layer "In2.Cu")
		(net "M_B_CPU1_SA_DQS_DP<2>")
	)
	(arc
		(start 86.092792 -265.803888)
		(mid 85.905594 -265.753745)
		(end 85.718396 -265.803888)
		(width 0.088646)
		(layer "In2.Cu")
		(net "M_B_CPU1_SA_DQS_DP<2>")
	)
	(arc
		(start 84.778596 -265.803888)
		(mid 84.544724 -265.877656)
		(end 84.301584 -265.845544)
		(width 0.088646)
		(layer "In2.Cu")
		(net "M_B_CPU1_SA_DQS_DP<2>")
	)
	(arc
		(start 84.08543 -265.831066)
		(mid 84.042725 -265.843482)
		(end 84.001864 -265.861038)
		(width 0.088646)
		(layer "In2.Cu")
		(net "M_B_CPU1_SA_DQS_DP<2>")
	)
	(arc
		(start 85.152992 -265.803888)
		(mid 84.965794 -265.753745)
		(end 84.778596 -265.803888)
		(width 0.088646)
		(layer "In2.Cu")
		(net "M_B_CPU1_SA_DQS_DP<2>")
	)
	(arc
		(start 87.032592 -265.803888)
		(mid 86.845394 -265.753745)
		(end 86.658196 -265.803888)
		(width 0.088646)
		(layer "In2.Cu")
		(net "M_B_CPU1_SA_DQS_DP<2>")
	)
	(arc
		(start 88.02751 -265.688064)
		(mid 87.804896 -265.717383)
		(end 87.597488 -265.80338)
		(width 0.088646)
		(layer "In2.Cu")
		(net "M_B_CPU1_SA_DQS_DP<2>")
	)
	(arc
		(start 88.442292 -265.638534)
		(mid 88.342625 -265.678235)
		(end 88.23579 -265.688064)
		(width 0.088646)
		(layer "In2.Cu")
		(net "M_B_CPU1_SA_DQS_DP<2>")
	)
	(arc
		(start 86.658196 -265.803888)
		(mid 86.375494 -265.87963)
		(end 86.092792 -265.803888)
		(width 0.088646)
		(layer "In2.Cu")
		(net "M_B_CPU1_SA_DQS_DP<2>")
	)
	(arc
		(start 84.301584 -265.845544)
		(mid 84.194545 -265.822771)
		(end 84.08543 -265.831066)
		(width 0.088646)
		(layer "In2.Cu")
		(net "M_B_CPU1_SA_DQS_DP<2>")
	)
	(segment
		(start 92.484448 -272.103342)
		(end 92.484448 -272.639028)
		(width 0.20066)
		(layer "F.Cu")
		(net "M_B_CPU1_SA_DQS_DP<1>")
	)
	(segment
		(start 39.11473 -303.305464)
		(end 38.853618 -303.566576)
		(width 0.20066)
		(layer "F.Cu")
		(net "M_B_CPU1_SA_DQS_DP<1>")
	)
	(segment
		(start 92.484448 -272.639028)
		(end 92.484194 -272.639282)
		(width 0.20066)
		(layer "F.Cu")
		(net "M_B_CPU1_SA_DQS_DP<1>")
	)
	(segment
		(start 41.073324 -304.00117)
		(end 40.802814 -303.73066)
		(width 0.20066)
		(layer "F.Cu")
		(net "M_B_CPU1_SA_DQS_DP<1>")
	)
	(segment
		(start 41.53789 -303.991772)
		(end 41.300908 -303.991772)
		(width 0.101854)
		(layer "F.Cu")
		(net "M_B_CPU1_SA_DQS_DP<1>")
	)
	(segment
		(start 45.310806 -303.566576)
		(end 45.049694 -303.305464)
		(width 0.20066)
		(layer "F.Cu")
		(net "M_B_CPU1_SA_DQS_DP<1>")
	)
	(segment
		(start 44.780962 -303.305464)
		(end 44.355766 -303.73066)
		(width 0.20066)
		(layer "F.Cu")
		(net "M_B_CPU1_SA_DQS_DP<1>")
	)
	(segment
		(start 41.300908 -303.991772)
		(end 41.29151 -304.00117)
		(width 0.101854)
		(layer "F.Cu")
		(net "M_B_CPU1_SA_DQS_DP<1>")
	)
	(segment
		(start 40.175688 -303.73066)
		(end 39.539672 -303.305464)
		(width 0.20066)
		(layer "F.Cu")
		(net "M_B_CPU1_SA_DQS_DP<1>")
	)
	(segment
		(start 43.616626 -303.991772)
		(end 43.293284 -303.991772)
		(width 0.101854)
		(layer "F.Cu")
		(net "M_B_CPU1_SA_DQS_DP<1>")
	)
	(segment
		(start 43.293284 -303.991772)
		(end 41.53789 -303.991772)
		(width 0.1016)
		(layer "F.Cu")
		(net "M_B_CPU1_SA_DQS_DP<1>")
	)
	(segment
		(start 41.29151 -304.00117)
		(end 41.073324 -304.00117)
		(width 0.20066)
		(layer "F.Cu")
		(net "M_B_CPU1_SA_DQS_DP<1>")
	)
	(segment
		(start 43.768772 -303.991772)
		(end 43.616626 -303.991772)
		(width 0.20066)
		(layer "F.Cu")
		(net "M_B_CPU1_SA_DQS_DP<1>")
	)
	(segment
		(start 38.853618 -303.566576)
		(end 38.315646 -303.566576)
		(width 0.20066)
		(layer "F.Cu")
		(net "M_B_CPU1_SA_DQS_DP<1>")
	)
	(segment
		(start 46.964346 -303.566576)
		(end 45.859446 -303.566576)
		(width 0.20066)
		(layer "F.Cu")
		(net "M_B_CPU1_SA_DQS_DP<1>")
	)
	(segment
		(start 39.539672 -303.305464)
		(end 39.11473 -303.305464)
		(width 0.20066)
		(layer "F.Cu")
		(net "M_B_CPU1_SA_DQS_DP<1>")
	)
	(segment
		(start 45.859446 -303.566576)
		(end 45.310806 -303.566576)
		(width 0.20066)
		(layer "F.Cu")
		(net "M_B_CPU1_SA_DQS_DP<1>")
	)
	(segment
		(start 40.802814 -303.73066)
		(end 40.175688 -303.73066)
		(width 0.20066)
		(layer "F.Cu")
		(net "M_B_CPU1_SA_DQS_DP<1>")
	)
	(segment
		(start 44.029884 -303.73066)
		(end 43.768772 -303.991772)
		(width 0.20066)
		(layer "F.Cu")
		(net "M_B_CPU1_SA_DQS_DP<1>")
	)
	(segment
		(start 44.355766 -303.73066)
		(end 44.029884 -303.73066)
		(width 0.20066)
		(layer "F.Cu")
		(net "M_B_CPU1_SA_DQS_DP<1>")
	)
	(segment
		(start 45.049694 -303.305464)
		(end 44.780962 -303.305464)
		(width 0.20066)
		(layer "F.Cu")
		(net "M_B_CPU1_SA_DQS_DP<1>")
	)
	(segment
		(start 50.094896 -303.715166)
		(end 49.413922 -303.034192)
		(width 0.18288)
		(layer "In4.Cu")
		(net "M_B_CPU1_SA_DQS_DP<1>")
	)
	(segment
		(start 86.188042 -274.756372)
		(end 86.186518 -274.757134)
		(width 0.088646)
		(layer "In4.Cu")
		(net "M_B_CPU1_SA_DQS_DP<1>")
	)
	(segment
		(start 77.089254 -284.536388)
		(end 73.640188 -292.91153)
		(width 0.18288)
		(layer "In4.Cu")
		(net "M_B_CPU1_SA_DQS_DP<1>")
	)
	(segment
		(start 85.118956 -276.49424)
		(end 85.118956 -277.040594)
		(width 0.088646)
		(layer "In4.Cu")
		(net "M_B_CPU1_SA_DQS_DP<1>")
	)
	(segment
		(start 83.313524 -278.323548)
		(end 83.239864 -278.397208)
		(width 0.18288)
		(layer "In4.Cu")
		(net "M_B_CPU1_SA_DQS_DP<1>")
	)
	(segment
		(start 91.452192 -273.008344)
		(end 91.096592 -273.008344)
		(width 0.088646)
		(layer "In4.Cu")
		(net "M_B_CPU1_SA_DQS_DP<1>")
	)
	(segment
		(start 64.214502 -300.336712)
		(end 62.492382 -300.336712)
		(width 0.18288)
		(layer "In4.Cu")
		(net "M_B_CPU1_SA_DQS_DP<1>")
	)
	(segment
		(start 86.190836 -274.754848)
		(end 86.188042 -274.756372)
		(width 0.088646)
		(layer "In4.Cu")
		(net "M_B_CPU1_SA_DQS_DP<1>")
	)
	(segment
		(start 83.348068 -278.204168)
		(end 83.348068 -278.289004)
		(width 0.088646)
		(layer "In4.Cu")
		(net "M_B_CPU1_SA_DQS_DP<1>")
	)
	(segment
		(start 61.143896 -300.297596)
		(end 59.606688 -301.325534)
		(width 0.18288)
		(layer "In4.Cu")
		(net "M_B_CPU1_SA_DQS_DP<1>")
	)
	(segment
		(start 73.640188 -292.91153)
		(end 67.112896 -299.438822)
		(width 0.18288)
		(layer "In4.Cu")
		(net "M_B_CPU1_SA_DQS_DP<1>")
	)
	(segment
		(start 50.5968 -303.715166)
		(end 50.094896 -303.715166)
		(width 0.18288)
		(layer "In4.Cu")
		(net "M_B_CPU1_SA_DQS_DP<1>")
	)
	(segment
		(start 85.118956 -277.040594)
		(end 84.044028 -278.115522)
		(width 0.088646)
		(layer "In4.Cu")
		(net "M_B_CPU1_SA_DQS_DP<1>")
	)
	(segment
		(start 86.186518 -274.757134)
		(end 86.179152 -274.761452)
		(width 0.088646)
		(layer "In4.Cu")
		(net "M_B_CPU1_SA_DQS_DP<1>")
	)
	(segment
		(start 86.658196 -273.942556)
		(end 86.656672 -273.943318)
		(width 0.088646)
		(layer "In4.Cu")
		(net "M_B_CPU1_SA_DQS_DP<1>")
	)
	(segment
		(start 57.847738 -303.084484)
		(end 56.206136 -303.084484)
		(width 0.18288)
		(layer "In4.Cu")
		(net "M_B_CPU1_SA_DQS_DP<1>")
	)
	(segment
		(start 66.628772 -299.438822)
		(end 66.329052 -299.738542)
		(width 0.18288)
		(layer "In4.Cu")
		(net "M_B_CPU1_SA_DQS_DP<1>")
	)
	(segment
		(start 89.007696 -273.12874)
		(end 88.992964 -273.137376)
		(width 0.088646)
		(layer "In4.Cu")
		(net "M_B_CPU1_SA_DQS_DP<1>")
	)
	(segment
		(start 65.977516 -299.738542)
		(end 65.69329 -299.454316)
		(width 0.18288)
		(layer "In4.Cu")
		(net "M_B_CPU1_SA_DQS_DP<1>")
	)
	(segment
		(start 51.511708 -303.723548)
		(end 51.243484 -303.991772)
		(width 0.18288)
		(layer "In4.Cu")
		(net "M_B_CPU1_SA_DQS_DP<1>")
	)
	(segment
		(start 62.492382 -300.336712)
		(end 62.237112 -300.591982)
		(width 0.18288)
		(layer "In4.Cu")
		(net "M_B_CPU1_SA_DQS_DP<1>")
	)
	(segment
		(start 50.873406 -303.991772)
		(end 50.5968 -303.715166)
		(width 0.18288)
		(layer "In4.Cu")
		(net "M_B_CPU1_SA_DQS_DP<1>")
	)
	(segment
		(start 47.81042 -303.285398)
		(end 47.245524 -303.285398)
		(width 0.18288)
		(layer "In4.Cu")
		(net "M_B_CPU1_SA_DQS_DP<1>")
	)
	(segment
		(start 62.237112 -300.591982)
		(end 61.85408 -300.591982)
		(width 0.18288)
		(layer "In4.Cu")
		(net "M_B_CPU1_SA_DQS_DP<1>")
	)
	(segment
		(start 85.718142 -275.570442)
		(end 85.71738 -275.57095)
		(width 0.088646)
		(layer "In4.Cu")
		(net "M_B_CPU1_SA_DQS_DP<1>")
	)
	(segment
		(start 56.206136 -303.084484)
		(end 54.663086 -303.723548)
		(width 0.18288)
		(layer "In4.Cu")
		(net "M_B_CPU1_SA_DQS_DP<1>")
	)
	(segment
		(start 86.664292 -273.939)
		(end 86.66099 -273.941032)
		(width 0.088646)
		(layer "In4.Cu")
		(net "M_B_CPU1_SA_DQS_DP<1>")
	)
	(segment
		(start 47.245524 -303.285398)
		(end 46.964346 -303.566576)
		(width 0.18288)
		(layer "In4.Cu")
		(net "M_B_CPU1_SA_DQS_DP<1>")
	)
	(segment
		(start 92.143834 -272.729198)
		(end 91.718638 -272.971006)
		(width 0.088646)
		(layer "In4.Cu")
		(net "M_B_CPU1_SA_DQS_DP<1>")
	)
	(segment
		(start 86.940898 -273.444462)
		(end 86.940898 -273.453098)
		(width 0.088646)
		(layer "In4.Cu")
		(net "M_B_CPU1_SA_DQS_DP<1>")
	)
	(segment
		(start 85.316822 -276.296374)
		(end 85.118956 -276.49424)
		(width 0.088646)
		(layer "In4.Cu")
		(net "M_B_CPU1_SA_DQS_DP<1>")
	)
	(segment
		(start 81.429352 -280.206958)
		(end 77.089254 -284.536388)
		(width 0.18288)
		(layer "In4.Cu")
		(net "M_B_CPU1_SA_DQS_DP<1>")
	)
	(segment
		(start 51.243484 -303.991772)
		(end 50.873406 -303.991772)
		(width 0.18288)
		(layer "In4.Cu")
		(net "M_B_CPU1_SA_DQS_DP<1>")
	)
	(segment
		(start 61.85408 -300.591982)
		(end 61.559694 -300.297596)
		(width 0.18288)
		(layer "In4.Cu")
		(net "M_B_CPU1_SA_DQS_DP<1>")
	)
	(segment
		(start 65.69329 -299.454316)
		(end 65.096898 -299.454316)
		(width 0.18288)
		(layer "In4.Cu")
		(net "M_B_CPU1_SA_DQS_DP<1>")
	)
	(segment
		(start 86.656672 -273.943318)
		(end 86.649306 -273.947636)
		(width 0.088646)
		(layer "In4.Cu")
		(net "M_B_CPU1_SA_DQS_DP<1>")
	)
	(segment
		(start 61.559694 -300.297596)
		(end 61.143896 -300.297596)
		(width 0.18288)
		(layer "In4.Cu")
		(net "M_B_CPU1_SA_DQS_DP<1>")
	)
	(segment
		(start 49.413922 -303.034192)
		(end 48.061626 -303.034192)
		(width 0.18288)
		(layer "In4.Cu")
		(net "M_B_CPU1_SA_DQS_DP<1>")
	)
	(segment
		(start 65.096898 -299.454316)
		(end 64.214502 -300.336712)
		(width 0.18288)
		(layer "In4.Cu")
		(net "M_B_CPU1_SA_DQS_DP<1>")
	)
	(segment
		(start 67.112896 -299.438822)
		(end 66.628772 -299.438822)
		(width 0.18288)
		(layer "In4.Cu")
		(net "M_B_CPU1_SA_DQS_DP<1>")
	)
	(segment
		(start 66.329052 -299.738542)
		(end 65.977516 -299.738542)
		(width 0.18288)
		(layer "In4.Cu")
		(net "M_B_CPU1_SA_DQS_DP<1>")
	)
	(segment
		(start 86.00059 -275.08073)
		(end 86.00059 -275.099272)
		(width 0.088646)
		(layer "In4.Cu")
		(net "M_B_CPU1_SA_DQS_DP<1>")
	)
	(segment
		(start 86.66099 -273.941032)
		(end 86.658196 -273.942556)
		(width 0.088646)
		(layer "In4.Cu")
		(net "M_B_CPU1_SA_DQS_DP<1>")
	)
	(segment
		(start 91.514168 -273.012662)
		(end 91.457018 -273.005804)
		(width 0.088646)
		(layer "In4.Cu")
		(net "M_B_CPU1_SA_DQS_DP<1>")
	)
	(segment
		(start 91.096592 -273.008344)
		(end 90.873072 -273.137122)
		(width 0.088646)
		(layer "In4.Cu")
		(net "M_B_CPU1_SA_DQS_DP<1>")
	)
	(segment
		(start 83.436968 -278.115522)
		(end 83.348068 -278.204168)
		(width 0.088646)
		(layer "In4.Cu")
		(net "M_B_CPU1_SA_DQS_DP<1>")
	)
	(segment
		(start 83.239864 -278.397208)
		(end 81.429352 -280.206958)
		(width 0.18288)
		(layer "In4.Cu")
		(net "M_B_CPU1_SA_DQS_DP<1>")
	)
	(segment
		(start 86.194138 -274.752816)
		(end 86.190836 -274.754848)
		(width 0.088646)
		(layer "In4.Cu")
		(net "M_B_CPU1_SA_DQS_DP<1>")
	)
	(segment
		(start 48.061626 -303.034192)
		(end 47.81042 -303.285398)
		(width 0.18288)
		(layer "In4.Cu")
		(net "M_B_CPU1_SA_DQS_DP<1>")
	)
	(segment
		(start 84.044028 -278.115522)
		(end 83.436968 -278.115522)
		(width 0.088646)
		(layer "In4.Cu")
		(net "M_B_CPU1_SA_DQS_DP<1>")
	)
	(segment
		(start 83.348068 -278.289004)
		(end 83.313524 -278.323548)
		(width 0.088646)
		(layer "In4.Cu")
		(net "M_B_CPU1_SA_DQS_DP<1>")
	)
	(segment
		(start 85.71738 -275.57095)
		(end 85.709252 -275.575522)
		(width 0.088646)
		(layer "In4.Cu")
		(net "M_B_CPU1_SA_DQS_DP<1>")
	)
	(segment
		(start 59.606688 -301.325534)
		(end 57.847738 -303.084484)
		(width 0.18288)
		(layer "In4.Cu")
		(net "M_B_CPU1_SA_DQS_DP<1>")
	)
	(segment
		(start 54.663086 -303.723548)
		(end 51.511708 -303.723548)
		(width 0.18288)
		(layer "In4.Cu")
		(net "M_B_CPU1_SA_DQS_DP<1>")
	)
	(segment
		(start 91.457018 -273.005804)
		(end 91.452192 -273.008344)
		(width 0.088646)
		(layer "In4.Cu")
		(net "M_B_CPU1_SA_DQS_DP<1>")
	)
	(arc
		(start 89.947496 -273.12874)
		(mid 89.664794 -273.204516)
		(end 89.382092 -273.12874)
		(width 0.088646)
		(layer "In4.Cu")
		(net "M_B_CPU1_SA_DQS_DP<1>")
	)
	(arc
		(start 86.00059 -275.099272)
		(mid 85.920428 -275.371461)
		(end 85.718142 -275.570442)
		(width 0.088646)
		(layer "In4.Cu")
		(net "M_B_CPU1_SA_DQS_DP<1>")
	)
	(arc
		(start 86.649306 -273.947636)
		(mid 86.518392 -274.083996)
		(end 86.470744 -274.266914)
		(width 0.088646)
		(layer "In4.Cu")
		(net "M_B_CPU1_SA_DQS_DP<1>")
	)
	(arc
		(start 85.532722 -275.85035)
		(mid 85.462346 -276.091545)
		(end 85.316822 -276.296374)
		(width 0.088646)
		(layer "In4.Cu")
		(net "M_B_CPU1_SA_DQS_DP<1>")
	)
	(arc
		(start 88.992964 -273.137376)
		(mid 88.716489 -273.204696)
		(end 88.442292 -273.12874)
		(width 0.088646)
		(layer "In4.Cu")
		(net "M_B_CPU1_SA_DQS_DP<1>")
	)
	(arc
		(start 87.128096 -273.12874)
		(mid 86.993163 -273.262094)
		(end 86.940898 -273.444462)
		(width 0.088646)
		(layer "In4.Cu")
		(net "M_B_CPU1_SA_DQS_DP<1>")
	)
	(arc
		(start 88.442292 -273.12874)
		(mid 88.255094 -273.078597)
		(end 88.067896 -273.12874)
		(width 0.088646)
		(layer "In4.Cu")
		(net "M_B_CPU1_SA_DQS_DP<1>")
	)
	(arc
		(start 86.179152 -274.761452)
		(mid 86.048238 -274.897812)
		(end 86.00059 -275.08073)
		(width 0.088646)
		(layer "In4.Cu")
		(net "M_B_CPU1_SA_DQS_DP<1>")
	)
	(arc
		(start 92.484194 -272.639282)
		(mid 92.308173 -272.662119)
		(end 92.143834 -272.729198)
		(width 0.088646)
		(layer "In4.Cu")
		(net "M_B_CPU1_SA_DQS_DP<1>")
	)
	(arc
		(start 86.940898 -273.453098)
		(mid 86.866907 -273.732664)
		(end 86.664292 -273.939)
		(width 0.088646)
		(layer "In4.Cu")
		(net "M_B_CPU1_SA_DQS_DP<1>")
	)
	(arc
		(start 85.709252 -275.575522)
		(mid 85.589534 -275.692722)
		(end 85.532722 -275.85035)
		(width 0.088646)
		(layer "In4.Cu")
		(net "M_B_CPU1_SA_DQS_DP<1>")
	)
	(arc
		(start 91.718638 -272.971006)
		(mid 91.619796 -273.008516)
		(end 91.514168 -273.012662)
		(width 0.088646)
		(layer "In4.Cu")
		(net "M_B_CPU1_SA_DQS_DP<1>")
	)
	(arc
		(start 87.502492 -273.12874)
		(mid 87.315294 -273.078597)
		(end 87.128096 -273.12874)
		(width 0.088646)
		(layer "In4.Cu")
		(net "M_B_CPU1_SA_DQS_DP<1>")
	)
	(arc
		(start 88.067896 -273.12874)
		(mid 87.785194 -273.204516)
		(end 87.502492 -273.12874)
		(width 0.088646)
		(layer "In4.Cu")
		(net "M_B_CPU1_SA_DQS_DP<1>")
	)
	(arc
		(start 89.382092 -273.12874)
		(mid 89.194894 -273.078597)
		(end 89.007696 -273.12874)
		(width 0.088646)
		(layer "In4.Cu")
		(net "M_B_CPU1_SA_DQS_DP<1>")
	)
	(arc
		(start 90.873072 -273.137122)
		(mid 90.596407 -273.204593)
		(end 90.321892 -273.12874)
		(width 0.088646)
		(layer "In4.Cu")
		(net "M_B_CPU1_SA_DQS_DP<1>")
	)
	(arc
		(start 86.470744 -274.266914)
		(mid 86.396753 -274.54648)
		(end 86.194138 -274.752816)
		(width 0.088646)
		(layer "In4.Cu")
		(net "M_B_CPU1_SA_DQS_DP<1>")
	)
	(arc
		(start 90.321892 -273.12874)
		(mid 90.134694 -273.078597)
		(end 89.947496 -273.12874)
		(width 0.088646)
		(layer "In4.Cu")
		(net "M_B_CPU1_SA_DQS_DP<1>")
	)
	(segment
		(start 46.964346 -312.91657)
		(end 45.859446 -312.91657)
		(width 0.20066)
		(layer "F.Cu")
		(net "M_B_CPU1_SA_DQS_DP<0>")
	)
	(segment
		(start 39.539672 -312.655458)
		(end 39.11473 -312.655458)
		(width 0.20066)
		(layer "F.Cu")
		(net "M_B_CPU1_SA_DQS_DP<0>")
	)
	(segment
		(start 89.194894 -274.54479)
		(end 89.194894 -275.08073)
		(width 0.20066)
		(layer "F.Cu")
		(net "M_B_CPU1_SA_DQS_DP<0>")
	)
	(segment
		(start 41.53789 -313.341766)
		(end 41.300908 -313.341766)
		(width 0.101854)
		(layer "F.Cu")
		(net "M_B_CPU1_SA_DQS_DP<0>")
	)
	(segment
		(start 44.780962 -312.655458)
		(end 44.355766 -313.080654)
		(width 0.20066)
		(layer "F.Cu")
		(net "M_B_CPU1_SA_DQS_DP<0>")
	)
	(segment
		(start 44.355766 -313.080654)
		(end 44.029884 -313.080654)
		(width 0.20066)
		(layer "F.Cu")
		(net "M_B_CPU1_SA_DQS_DP<0>")
	)
	(segment
		(start 43.616626 -313.341766)
		(end 43.293284 -313.341766)
		(width 0.101854)
		(layer "F.Cu")
		(net "M_B_CPU1_SA_DQS_DP<0>")
	)
	(segment
		(start 40.802814 -313.080654)
		(end 40.175688 -313.080654)
		(width 0.20066)
		(layer "F.Cu")
		(net "M_B_CPU1_SA_DQS_DP<0>")
	)
	(segment
		(start 45.859446 -312.91657)
		(end 45.310806 -312.91657)
		(width 0.20066)
		(layer "F.Cu")
		(net "M_B_CPU1_SA_DQS_DP<0>")
	)
	(segment
		(start 39.11473 -312.655458)
		(end 38.853618 -312.91657)
		(width 0.20066)
		(layer "F.Cu")
		(net "M_B_CPU1_SA_DQS_DP<0>")
	)
	(segment
		(start 38.853618 -312.91657)
		(end 38.315646 -312.91657)
		(width 0.20066)
		(layer "F.Cu")
		(net "M_B_CPU1_SA_DQS_DP<0>")
	)
	(segment
		(start 41.29151 -313.351164)
		(end 41.073324 -313.351164)
		(width 0.20066)
		(layer "F.Cu")
		(net "M_B_CPU1_SA_DQS_DP<0>")
	)
	(segment
		(start 40.175688 -313.080654)
		(end 39.539672 -312.655458)
		(width 0.20066)
		(layer "F.Cu")
		(net "M_B_CPU1_SA_DQS_DP<0>")
	)
	(segment
		(start 41.073324 -313.351164)
		(end 40.802814 -313.080654)
		(width 0.20066)
		(layer "F.Cu")
		(net "M_B_CPU1_SA_DQS_DP<0>")
	)
	(segment
		(start 44.029884 -313.080654)
		(end 43.768772 -313.341766)
		(width 0.20066)
		(layer "F.Cu")
		(net "M_B_CPU1_SA_DQS_DP<0>")
	)
	(segment
		(start 41.300908 -313.341766)
		(end 41.29151 -313.351164)
		(width 0.101854)
		(layer "F.Cu")
		(net "M_B_CPU1_SA_DQS_DP<0>")
	)
	(segment
		(start 45.310806 -312.91657)
		(end 45.049694 -312.655458)
		(width 0.20066)
		(layer "F.Cu")
		(net "M_B_CPU1_SA_DQS_DP<0>")
	)
	(segment
		(start 45.049694 -312.655458)
		(end 44.780962 -312.655458)
		(width 0.20066)
		(layer "F.Cu")
		(net "M_B_CPU1_SA_DQS_DP<0>")
	)
	(segment
		(start 43.293284 -313.341766)
		(end 41.53789 -313.341766)
		(width 0.1016)
		(layer "F.Cu")
		(net "M_B_CPU1_SA_DQS_DP<0>")
	)
	(segment
		(start 43.768772 -313.341766)
		(end 43.616626 -313.341766)
		(width 0.20066)
		(layer "F.Cu")
		(net "M_B_CPU1_SA_DQS_DP<0>")
	)
	(segment
		(start 66.12382 -312.537094)
		(end 65.923668 -312.737246)
		(width 0.16002)
		(layer "In2.Cu")
		(net "M_B_CPU1_SA_DQS_DP<0>")
	)
	(segment
		(start 87.597488 -278.826214)
		(end 87.586058 -278.832818)
		(width 0.088646)
		(layer "In2.Cu")
		(net "M_B_CPU1_SA_DQS_DP<0>")
	)
	(segment
		(start 49.139094 -312.813954)
		(end 49.1109 -312.78576)
		(width 0.16002)
		(layer "In2.Cu")
		(net "M_B_CPU1_SA_DQS_DP<0>")
	)
	(segment
		(start 83.524598 -283.991812)
		(end 83.316318 -284.494986)
		(width 0.18288)
		(layer "In2.Cu")
		(net "M_B_CPU1_SA_DQS_DP<0>")
	)
	(segment
		(start 59.28868 -313.839098)
		(end 58.993786 -313.839098)
		(width 0.18288)
		(layer "In2.Cu")
		(net "M_B_CPU1_SA_DQS_DP<0>")
	)
	(segment
		(start 88.167718 -275.447252)
		(end 88.162892 -275.449792)
		(width 0.088646)
		(layer "In2.Cu")
		(net "M_B_CPU1_SA_DQS_DP<0>")
	)
	(segment
		(start 83.316318 -284.494986)
		(end 82.685128 -286.019748)
		(width 0.18288)
		(layer "In2.Cu")
		(net "M_B_CPU1_SA_DQS_DP<0>")
	)
	(segment
		(start 58.68416 -314.132976)
		(end 58.484008 -314.333128)
		(width 0.16002)
		(layer "In2.Cu")
		(net "M_B_CPU1_SA_DQS_DP<0>")
	)
	(segment
		(start 51.556666 -313.028076)
		(end 51.242214 -313.342528)
		(width 0.18288)
		(layer "In2.Cu")
		(net "M_B_CPU1_SA_DQS_DP<0>")
	)
	(segment
		(start 65.923668 -312.752994)
		(end 65.895474 -312.781188)
		(width 0.16002)
		(layer "In2.Cu")
		(net "M_B_CPU1_SA_DQS_DP<0>")
	)
	(segment
		(start 87.928958 -275.449792)
		(end 87.69858 -275.511514)
		(width 0.088646)
		(layer "In2.Cu")
		(net "M_B_CPU1_SA_DQS_DP<0>")
	)
	(segment
		(start 66.167762 -312.5089)
		(end 66.139568 -312.537094)
		(width 0.16002)
		(layer "In2.Cu")
		(net "M_B_CPU1_SA_DQS_DP<0>")
	)
	(segment
		(start 88.067134 -278.012398)
		(end 88.058244 -278.017478)
		(width 0.088646)
		(layer "In2.Cu")
		(net "M_B_CPU1_SA_DQS_DP<0>")
	)
	(segment
		(start 58.258456 -314.574428)
		(end 56.748172 -314.574428)
		(width 0.18288)
		(layer "In2.Cu")
		(net "M_B_CPU1_SA_DQS_DP<0>")
	)
	(segment
		(start 87.132922 -279.636982)
		(end 87.13216 -279.63749)
		(width 0.088646)
		(layer "In2.Cu")
		(net "M_B_CPU1_SA_DQS_DP<0>")
	)
	(segment
		(start 85.437218 -280.003504)
		(end 85.437218 -280.08834)
		(width 0.088646)
		(layer "In2.Cu")
		(net "M_B_CPU1_SA_DQS_DP<0>")
	)
	(segment
		(start 47.212504 -312.668412)
		(end 46.964346 -312.91657)
		(width 0.18288)
		(layer "In2.Cu")
		(net "M_B_CPU1_SA_DQS_DP<0>")
	)
	(segment
		(start 52.450746 -313.526932)
		(end 52.422552 -313.498738)
		(width 0.16002)
		(layer "In2.Cu")
		(net "M_B_CPU1_SA_DQS_DP<0>")
	)
	(segment
		(start 67.870832 -311.715404)
		(end 66.313812 -312.36285)
		(width 0.18288)
		(layer "In2.Cu")
		(net "M_B_CPU1_SA_DQS_DP<0>")
	)
	(segment
		(start 85.437218 -280.08834)
		(end 83.524598 -282.00096)
		(width 0.18288)
		(layer "In2.Cu")
		(net "M_B_CPU1_SA_DQS_DP<0>")
	)
	(segment
		(start 82.685128 -286.019748)
		(end 80.141064 -288.564066)
		(width 0.18288)
		(layer "In2.Cu")
		(net "M_B_CPU1_SA_DQS_DP<0>")
	)
	(segment
		(start 74.805032 -302.962818)
		(end 73.519538 -306.066952)
		(width 0.18288)
		(layer "In2.Cu")
		(net "M_B_CPU1_SA_DQS_DP<0>")
	)
	(segment
		(start 87.60841 -278.819864)
		(end 87.597488 -278.826214)
		(width 0.088646)
		(layer "In2.Cu")
		(net "M_B_CPU1_SA_DQS_DP<0>")
	)
	(segment
		(start 65.605152 -313.07151)
		(end 64.174878 -313.07151)
		(width 0.18288)
		(layer "In2.Cu")
		(net "M_B_CPU1_SA_DQS_DP<0>")
	)
	(segment
		(start 52.648104 -313.72429)
		(end 52.450746 -313.526932)
		(width 0.18288)
		(layer "In2.Cu")
		(net "M_B_CPU1_SA_DQS_DP<0>")
	)
	(segment
		(start 50.61204 -313.099958)
		(end 49.425098 -313.099958)
		(width 0.18288)
		(layer "In2.Cu")
		(net "M_B_CPU1_SA_DQS_DP<0>")
	)
	(segment
		(start 63.54953 -313.34329)
		(end 63.27775 -313.07151)
		(width 0.18288)
		(layer "In2.Cu")
		(net "M_B_CPU1_SA_DQS_DP<0>")
	)
	(segment
		(start 88.083136 -278.003)
		(end 88.067134 -278.012398)
		(width 0.088646)
		(layer "In2.Cu")
		(net "M_B_CPU1_SA_DQS_DP<0>")
	)
	(segment
		(start 87.88019 -276.708616)
		(end 87.880444 -276.708616)
		(width 0.088646)
		(layer "In2.Cu")
		(net "M_B_CPU1_SA_DQS_DP<0>")
	)
	(segment
		(start 48.71847 -312.39333)
		(end 48.198278 -312.39333)
		(width 0.18288)
		(layer "In2.Cu")
		(net "M_B_CPU1_SA_DQS_DP<0>")
	)
	(segment
		(start 61.795406 -313.631072)
		(end 61.58738 -313.839098)
		(width 0.18288)
		(layer "In2.Cu")
		(net "M_B_CPU1_SA_DQS_DP<0>")
	)
	(segment
		(start 52.2224 -313.282838)
		(end 52.206652 -313.282838)
		(width 0.16002)
		(layer "In2.Cu")
		(net "M_B_CPU1_SA_DQS_DP<0>")
	)
	(segment
		(start 58.699908 -314.132976)
		(end 58.68416 -314.132976)
		(width 0.16002)
		(layer "In2.Cu")
		(net "M_B_CPU1_SA_DQS_DP<0>")
	)
	(segment
		(start 88.947752 -275.327872)
		(end 88.577928 -275.327872)
		(width 0.088646)
		(layer "In2.Cu")
		(net "M_B_CPU1_SA_DQS_DP<0>")
	)
	(segment
		(start 83.524598 -282.00096)
		(end 83.524598 -283.991812)
		(width 0.18288)
		(layer "In2.Cu")
		(net "M_B_CPU1_SA_DQS_DP<0>")
	)
	(segment
		(start 56.748172 -314.574428)
		(end 56.550814 -314.37707)
		(width 0.18288)
		(layer "In2.Cu")
		(net "M_B_CPU1_SA_DQS_DP<0>")
	)
	(segment
		(start 87.597996 -276.219158)
		(end 87.603838 -276.222714)
		(width 0.088646)
		(layer "In2.Cu")
		(net "M_B_CPU1_SA_DQS_DP<0>")
	)
	(segment
		(start 52.206652 -313.282838)
		(end 52.178458 -313.254644)
		(width 0.16002)
		(layer "In2.Cu")
		(net "M_B_CPU1_SA_DQS_DP<0>")
	)
	(segment
		(start 88.224868 -275.45411)
		(end 88.167718 -275.447252)
		(width 0.088646)
		(layer "In2.Cu")
		(net "M_B_CPU1_SA_DQS_DP<0>")
	)
	(segment
		(start 87.58936 -275.57476)
		(end 87.588852 -275.575522)
		(width 0.088646)
		(layer "In2.Cu")
		(net "M_B_CPU1_SA_DQS_DP<0>")
	)
	(segment
		(start 86.186264 -279.625806)
		(end 86.186264 -279.625552)
		(width 0.088646)
		(layer "In2.Cu")
		(net "M_B_CPU1_SA_DQS_DP<0>")
	)
	(segment
		(start 54.355746 -313.526932)
		(end 54.158388 -313.72429)
		(width 0.18288)
		(layer "In2.Cu")
		(net "M_B_CPU1_SA_DQS_DP<0>")
	)
	(segment
		(start 86.037928 -279.767792)
		(end 85.67293 -279.767792)
		(width 0.088646)
		(layer "In2.Cu")
		(net "M_B_CPU1_SA_DQS_DP<0>")
	)
	(segment
		(start 61.8236 -313.602878)
		(end 61.795406 -313.631072)
		(width 0.16002)
		(layer "In2.Cu")
		(net "M_B_CPU1_SA_DQS_DP<0>")
	)
	(segment
		(start 49.425098 -313.099958)
		(end 49.139094 -312.813954)
		(width 0.18288)
		(layer "In2.Cu")
		(net "M_B_CPU1_SA_DQS_DP<0>")
	)
	(segment
		(start 75.38593 -300.041818)
		(end 74.805032 -302.962818)
		(width 0.18288)
		(layer "In2.Cu")
		(net "M_B_CPU1_SA_DQS_DP<0>")
	)
	(segment
		(start 64.174878 -313.07151)
		(end 63.903098 -313.34329)
		(width 0.18288)
		(layer "In2.Cu")
		(net "M_B_CPU1_SA_DQS_DP<0>")
	)
	(segment
		(start 51.95189 -313.028076)
		(end 51.556666 -313.028076)
		(width 0.18288)
		(layer "In2.Cu")
		(net "M_B_CPU1_SA_DQS_DP<0>")
	)
	(segment
		(start 66.139568 -312.537094)
		(end 66.12382 -312.537094)
		(width 0.16002)
		(layer "In2.Cu")
		(net "M_B_CPU1_SA_DQS_DP<0>")
	)
	(segment
		(start 47.534068 -312.668412)
		(end 47.212504 -312.668412)
		(width 0.18288)
		(layer "In2.Cu")
		(net "M_B_CPU1_SA_DQS_DP<0>")
	)
	(segment
		(start 48.895 -312.56986)
		(end 48.866806 -312.541666)
		(width 0.16002)
		(layer "In2.Cu")
		(net "M_B_CPU1_SA_DQS_DP<0>")
	)
	(segment
		(start 87.880444 -276.708616)
		(end 87.880444 -276.720554)
		(width 0.088646)
		(layer "In2.Cu")
		(net "M_B_CPU1_SA_DQS_DP<0>")
	)
	(segment
		(start 86.174834 -279.634442)
		(end 86.173818 -279.635204)
		(width 0.088646)
		(layer "In2.Cu")
		(net "M_B_CPU1_SA_DQS_DP<0>")
	)
	(segment
		(start 55.288434 -313.11469)
		(end 54.767988 -313.11469)
		(width 0.18288)
		(layer "In2.Cu")
		(net "M_B_CPU1_SA_DQS_DP<0>")
	)
	(segment
		(start 56.52262 -314.348876)
		(end 56.52262 -314.333128)
		(width 0.16002)
		(layer "In2.Cu")
		(net "M_B_CPU1_SA_DQS_DP<0>")
	)
	(segment
		(start 58.993786 -313.839098)
		(end 58.728102 -314.104782)
		(width 0.18288)
		(layer "In2.Cu")
		(net "M_B_CPU1_SA_DQS_DP<0>")
	)
	(segment
		(start 59.914028 -314.110878)
		(end 59.56046 -314.110878)
		(width 0.18288)
		(layer "In2.Cu")
		(net "M_B_CPU1_SA_DQS_DP<0>")
	)
	(segment
		(start 56.550814 -314.37707)
		(end 56.52262 -314.348876)
		(width 0.16002)
		(layer "In2.Cu")
		(net "M_B_CPU1_SA_DQS_DP<0>")
	)
	(segment
		(start 54.38394 -313.498738)
		(end 54.355746 -313.526932)
		(width 0.16002)
		(layer "In2.Cu")
		(net "M_B_CPU1_SA_DQS_DP<0>")
	)
	(segment
		(start 58.728102 -314.104782)
		(end 58.699908 -314.132976)
		(width 0.16002)
		(layer "In2.Cu")
		(net "M_B_CPU1_SA_DQS_DP<0>")
	)
	(segment
		(start 52.178458 -313.254644)
		(end 51.95189 -313.028076)
		(width 0.18288)
		(layer "In2.Cu")
		(net "M_B_CPU1_SA_DQS_DP<0>")
	)
	(segment
		(start 86.574884 -279.64638)
		(end 86.538308 -279.625298)
		(width 0.088646)
		(layer "In2.Cu")
		(net "M_B_CPU1_SA_DQS_DP<0>")
	)
	(segment
		(start 87.41029 -275.8948)
		(end 87.410544 -275.893784)
		(width 0.088646)
		(layer "In2.Cu")
		(net "M_B_CPU1_SA_DQS_DP<0>")
	)
	(segment
		(start 56.30672 -314.132976)
		(end 56.278526 -314.104782)
		(width 0.16002)
		(layer "In2.Cu")
		(net "M_B_CPU1_SA_DQS_DP<0>")
	)
	(segment
		(start 62.0395 -313.386978)
		(end 62.023752 -313.386978)
		(width 0.16002)
		(layer "In2.Cu")
		(net "M_B_CPU1_SA_DQS_DP<0>")
	)
	(segment
		(start 85.67293 -279.767792)
		(end 85.437218 -280.003504)
		(width 0.088646)
		(layer "In2.Cu")
		(net "M_B_CPU1_SA_DQS_DP<0>")
	)
	(segment
		(start 61.8236 -313.58713)
		(end 61.8236 -313.602878)
		(width 0.16002)
		(layer "In2.Cu")
		(net "M_B_CPU1_SA_DQS_DP<0>")
	)
	(segment
		(start 54.38394 -313.48299)
		(end 54.38394 -313.498738)
		(width 0.16002)
		(layer "In2.Cu")
		(net "M_B_CPU1_SA_DQS_DP<0>")
	)
	(segment
		(start 63.903098 -313.34329)
		(end 63.54953 -313.34329)
		(width 0.18288)
		(layer "In2.Cu")
		(net "M_B_CPU1_SA_DQS_DP<0>")
	)
	(segment
		(start 50.85461 -313.342528)
		(end 50.61204 -313.099958)
		(width 0.18288)
		(layer "In2.Cu")
		(net "M_B_CPU1_SA_DQS_DP<0>")
	)
	(segment
		(start 88.349836 -277.508462)
		(end 88.35009 -277.522686)
		(width 0.088646)
		(layer "In2.Cu")
		(net "M_B_CPU1_SA_DQS_DP<0>")
	)
	(segment
		(start 62.067694 -313.358784)
		(end 62.0395 -313.386978)
		(width 0.16002)
		(layer "In2.Cu")
		(net "M_B_CPU1_SA_DQS_DP<0>")
	)
	(segment
		(start 87.589106 -276.214078)
		(end 87.597996 -276.219158)
		(width 0.088646)
		(layer "In2.Cu")
		(net "M_B_CPU1_SA_DQS_DP<0>")
	)
	(segment
		(start 48.910748 -312.56986)
		(end 48.895 -312.56986)
		(width 0.16002)
		(layer "In2.Cu")
		(net "M_B_CPU1_SA_DQS_DP<0>")
	)
	(segment
		(start 49.1109 -312.770012)
		(end 48.910748 -312.56986)
		(width 0.16002)
		(layer "In2.Cu")
		(net "M_B_CPU1_SA_DQS_DP<0>")
	)
	(segment
		(start 60.185808 -313.839098)
		(end 59.914028 -314.110878)
		(width 0.18288)
		(layer "In2.Cu")
		(net "M_B_CPU1_SA_DQS_DP<0>")
	)
	(segment
		(start 65.895474 -312.781188)
		(end 65.605152 -313.07151)
		(width 0.18288)
		(layer "In2.Cu")
		(net "M_B_CPU1_SA_DQS_DP<0>")
	)
	(segment
		(start 54.59984 -313.282838)
		(end 54.584092 -313.282838)
		(width 0.16002)
		(layer "In2.Cu")
		(net "M_B_CPU1_SA_DQS_DP<0>")
	)
	(segment
		(start 58.484008 -314.333128)
		(end 58.484008 -314.348876)
		(width 0.16002)
		(layer "In2.Cu")
		(net "M_B_CPU1_SA_DQS_DP<0>")
	)
	(segment
		(start 86.57717 -279.648666)
		(end 86.574884 -279.64638)
		(width 0.088646)
		(layer "In2.Cu")
		(net "M_B_CPU1_SA_DQS_DP<0>")
	)
	(segment
		(start 87.13216 -279.63749)
		(end 87.13089 -279.638252)
		(width 0.088646)
		(layer "In2.Cu")
		(net "M_B_CPU1_SA_DQS_DP<0>")
	)
	(segment
		(start 56.52262 -314.333128)
		(end 56.322468 -314.132976)
		(width 0.16002)
		(layer "In2.Cu")
		(net "M_B_CPU1_SA_DQS_DP<0>")
	)
	(segment
		(start 54.628034 -313.254644)
		(end 54.59984 -313.282838)
		(width 0.16002)
		(layer "In2.Cu")
		(net "M_B_CPU1_SA_DQS_DP<0>")
	)
	(segment
		(start 63.27775 -313.07151)
		(end 62.354968 -313.07151)
		(width 0.18288)
		(layer "In2.Cu")
		(net "M_B_CPU1_SA_DQS_DP<0>")
	)
	(segment
		(start 89.194894 -275.08073)
		(end 88.947752 -275.327872)
		(width 0.088646)
		(layer "In2.Cu")
		(net "M_B_CPU1_SA_DQS_DP<0>")
	)
	(segment
		(start 87.69858 -275.511514)
		(end 87.58936 -275.57476)
		(width 0.088646)
		(layer "In2.Cu")
		(net "M_B_CPU1_SA_DQS_DP<0>")
	)
	(segment
		(start 54.158388 -313.72429)
		(end 52.648104 -313.72429)
		(width 0.18288)
		(layer "In2.Cu")
		(net "M_B_CPU1_SA_DQS_DP<0>")
	)
	(segment
		(start 49.1109 -312.78576)
		(end 49.1109 -312.770012)
		(width 0.16002)
		(layer "In2.Cu")
		(net "M_B_CPU1_SA_DQS_DP<0>")
	)
	(segment
		(start 56.322468 -314.132976)
		(end 56.30672 -314.132976)
		(width 0.16002)
		(layer "In2.Cu")
		(net "M_B_CPU1_SA_DQS_DP<0>")
	)
	(segment
		(start 62.023752 -313.386978)
		(end 61.8236 -313.58713)
		(width 0.16002)
		(layer "In2.Cu")
		(net "M_B_CPU1_SA_DQS_DP<0>")
	)
	(segment
		(start 88.162892 -275.449792)
		(end 87.928958 -275.449792)
		(width 0.088646)
		(layer "In2.Cu")
		(net "M_B_CPU1_SA_DQS_DP<0>")
	)
	(segment
		(start 88.577928 -275.327872)
		(end 88.429338 -275.412454)
		(width 0.088646)
		(layer "In2.Cu")
		(net "M_B_CPU1_SA_DQS_DP<0>")
	)
	(segment
		(start 65.923668 -312.737246)
		(end 65.923668 -312.752994)
		(width 0.16002)
		(layer "In2.Cu")
		(net "M_B_CPU1_SA_DQS_DP<0>")
	)
	(segment
		(start 86.173818 -279.635204)
		(end 86.037928 -279.767792)
		(width 0.088646)
		(layer "In2.Cu")
		(net "M_B_CPU1_SA_DQS_DP<0>")
	)
	(segment
		(start 87.129874 -279.63876)
		(end 87.127842 -279.64003)
		(width 0.088646)
		(layer "In2.Cu")
		(net "M_B_CPU1_SA_DQS_DP<0>")
	)
	(segment
		(start 56.278526 -314.104782)
		(end 55.288434 -313.11469)
		(width 0.18288)
		(layer "In2.Cu")
		(net "M_B_CPU1_SA_DQS_DP<0>")
	)
	(segment
		(start 66.313812 -312.36285)
		(end 66.167762 -312.5089)
		(width 0.18288)
		(layer "In2.Cu")
		(net "M_B_CPU1_SA_DQS_DP<0>")
	)
	(segment
		(start 80.141064 -288.564066)
		(end 75.38593 -300.041818)
		(width 0.18288)
		(layer "In2.Cu")
		(net "M_B_CPU1_SA_DQS_DP<0>")
	)
	(segment
		(start 58.455814 -314.37707)
		(end 58.258456 -314.574428)
		(width 0.18288)
		(layer "In2.Cu")
		(net "M_B_CPU1_SA_DQS_DP<0>")
	)
	(segment
		(start 54.767988 -313.11469)
		(end 54.628034 -313.254644)
		(width 0.18288)
		(layer "In2.Cu")
		(net "M_B_CPU1_SA_DQS_DP<0>")
	)
	(segment
		(start 52.422552 -313.48299)
		(end 52.2224 -313.282838)
		(width 0.16002)
		(layer "In2.Cu")
		(net "M_B_CPU1_SA_DQS_DP<0>")
	)
	(segment
		(start 87.13089 -279.638252)
		(end 87.129874 -279.63876)
		(width 0.088646)
		(layer "In2.Cu")
		(net "M_B_CPU1_SA_DQS_DP<0>")
	)
	(segment
		(start 48.198278 -312.39333)
		(end 47.534068 -312.668412)
		(width 0.18288)
		(layer "In2.Cu")
		(net "M_B_CPU1_SA_DQS_DP<0>")
	)
	(segment
		(start 48.866806 -312.541666)
		(end 48.71847 -312.39333)
		(width 0.18288)
		(layer "In2.Cu")
		(net "M_B_CPU1_SA_DQS_DP<0>")
	)
	(segment
		(start 87.609172 -276.225762)
		(end 87.609172 -276.226016)
		(width 0.088646)
		(layer "In2.Cu")
		(net "M_B_CPU1_SA_DQS_DP<0>")
	)
	(segment
		(start 73.519538 -306.066952)
		(end 67.870832 -311.715404)
		(width 0.18288)
		(layer "In2.Cu")
		(net "M_B_CPU1_SA_DQS_DP<0>")
	)
	(segment
		(start 58.484008 -314.348876)
		(end 58.455814 -314.37707)
		(width 0.16002)
		(layer "In2.Cu")
		(net "M_B_CPU1_SA_DQS_DP<0>")
	)
	(segment
		(start 59.56046 -314.110878)
		(end 59.28868 -313.839098)
		(width 0.18288)
		(layer "In2.Cu")
		(net "M_B_CPU1_SA_DQS_DP<0>")
	)
	(segment
		(start 51.242214 -313.342528)
		(end 50.85461 -313.342528)
		(width 0.18288)
		(layer "In2.Cu")
		(net "M_B_CPU1_SA_DQS_DP<0>")
	)
	(segment
		(start 87.133938 -279.636474)
		(end 87.132922 -279.636982)
		(width 0.088646)
		(layer "In2.Cu")
		(net "M_B_CPU1_SA_DQS_DP<0>")
	)
	(segment
		(start 61.58738 -313.839098)
		(end 60.185808 -313.839098)
		(width 0.18288)
		(layer "In2.Cu")
		(net "M_B_CPU1_SA_DQS_DP<0>")
	)
	(segment
		(start 52.422552 -313.498738)
		(end 52.422552 -313.48299)
		(width 0.16002)
		(layer "In2.Cu")
		(net "M_B_CPU1_SA_DQS_DP<0>")
	)
	(segment
		(start 54.584092 -313.282838)
		(end 54.38394 -313.48299)
		(width 0.16002)
		(layer "In2.Cu")
		(net "M_B_CPU1_SA_DQS_DP<0>")
	)
	(segment
		(start 62.354968 -313.07151)
		(end 62.067694 -313.358784)
		(width 0.18288)
		(layer "In2.Cu")
		(net "M_B_CPU1_SA_DQS_DP<0>")
	)
	(arc
		(start 87.127842 -279.64003)
		(mid 86.853643 -279.715865)
		(end 86.57717 -279.648666)
		(width 0.088646)
		(layer "In2.Cu")
		(net "M_B_CPU1_SA_DQS_DP<0>")
	)
	(arc
		(start 87.880444 -276.720554)
		(mid 87.933491 -276.901168)
		(end 88.067642 -277.033228)
		(width 0.088646)
		(layer "In2.Cu")
		(net "M_B_CPU1_SA_DQS_DP<0>")
	)
	(arc
		(start 87.586058 -278.832818)
		(mid 87.457167 -278.968866)
		(end 87.41029 -279.150318)
		(width 0.088646)
		(layer "In2.Cu")
		(net "M_B_CPU1_SA_DQS_DP<0>")
	)
	(arc
		(start 87.609172 -276.226016)
		(mid 87.807813 -276.431865)
		(end 87.88019 -276.708616)
		(width 0.088646)
		(layer "In2.Cu")
		(net "M_B_CPU1_SA_DQS_DP<0>")
	)
	(arc
		(start 88.058244 -278.017478)
		(mid 87.92733 -278.153838)
		(end 87.879682 -278.336756)
		(width 0.088646)
		(layer "In2.Cu")
		(net "M_B_CPU1_SA_DQS_DP<0>")
	)
	(arc
		(start 86.186264 -279.625552)
		(mid 86.180255 -279.629619)
		(end 86.174834 -279.634442)
		(width 0.088646)
		(layer "In2.Cu")
		(net "M_B_CPU1_SA_DQS_DP<0>")
	)
	(arc
		(start 88.067642 -277.033228)
		(mid 88.270702 -277.234037)
		(end 88.349836 -277.508462)
		(width 0.088646)
		(layer "In2.Cu")
		(net "M_B_CPU1_SA_DQS_DP<0>")
	)
	(arc
		(start 87.410544 -275.8948)
		(mid 87.458223 -276.0777)
		(end 87.589106 -276.214078)
		(width 0.088646)
		(layer "In2.Cu")
		(net "M_B_CPU1_SA_DQS_DP<0>")
	)
	(arc
		(start 87.879682 -278.336756)
		(mid 87.807286 -278.613823)
		(end 87.60841 -278.819864)
		(width 0.088646)
		(layer "In2.Cu")
		(net "M_B_CPU1_SA_DQS_DP<0>")
	)
	(arc
		(start 87.588852 -275.575522)
		(mid 87.457938 -275.711882)
		(end 87.41029 -275.8948)
		(width 0.088646)
		(layer "In2.Cu")
		(net "M_B_CPU1_SA_DQS_DP<0>")
	)
	(arc
		(start 88.429338 -275.412454)
		(mid 88.330496 -275.449964)
		(end 88.224868 -275.45411)
		(width 0.088646)
		(layer "In2.Cu")
		(net "M_B_CPU1_SA_DQS_DP<0>")
	)
	(arc
		(start 86.538308 -279.625298)
		(mid 86.362227 -279.578411)
		(end 86.186264 -279.625806)
		(width 0.088646)
		(layer "In2.Cu")
		(net "M_B_CPU1_SA_DQS_DP<0>")
	)
	(arc
		(start 87.410544 -275.893784)
		(mid 87.410544 -275.894292)
		(end 87.410544 -275.8948)
		(width 0.088646)
		(layer "In2.Cu")
		(net "M_B_CPU1_SA_DQS_DP<0>")
	)
	(arc
		(start 88.35009 -277.522686)
		(mid 88.278853 -277.797423)
		(end 88.083136 -278.003)
		(width 0.088646)
		(layer "In2.Cu")
		(net "M_B_CPU1_SA_DQS_DP<0>")
	)
	(arc
		(start 87.603838 -276.222714)
		(mid 87.606509 -276.224231)
		(end 87.609172 -276.225762)
		(width 0.088646)
		(layer "In2.Cu")
		(net "M_B_CPU1_SA_DQS_DP<0>")
	)
	(arc
		(start 87.41029 -279.150318)
		(mid 87.336437 -279.429964)
		(end 87.133938 -279.636474)
		(width 0.088646)
		(layer "In2.Cu")
		(net "M_B_CPU1_SA_DQS_DP<0>")
	)
	(segment
		(start 49.46904 -274.66671)
		(end 49.959514 -274.66671)
		(width 0.20066)
		(layer "F.Cu")
		(net "M_B_CPU1_SA_DQS_DN<9>")
	)
	(segment
		(start 47.060358 -274.241768)
		(end 47.202598 -274.241768)
		(width 0.20066)
		(layer "F.Cu")
		(net "M_B_CPU1_SA_DQS_DN<9>")
	)
	(segment
		(start 90.134694 -259.894832)
		(end 90.134694 -260.430518)
		(width 0.20066)
		(layer "F.Cu")
		(net "M_B_CPU1_SA_DQS_DN<9>")
	)
	(segment
		(start 49.207928 -274.405598)
		(end 49.46904 -274.66671)
		(width 0.20066)
		(layer "F.Cu")
		(net "M_B_CPU1_SA_DQS_DN<9>")
	)
	(segment
		(start 47.202598 -274.241768)
		(end 47.46371 -273.980656)
		(width 0.20066)
		(layer "F.Cu")
		(net "M_B_CPU1_SA_DQS_DN<9>")
	)
	(segment
		(start 44.744894 -274.241768)
		(end 44.982892 -274.241768)
		(width 0.101854)
		(layer "F.Cu")
		(net "M_B_CPU1_SA_DQS_DN<9>")
	)
	(segment
		(start 90.134694 -260.430518)
		(end 90.134948 -260.430772)
		(width 0.20066)
		(layer "F.Cu")
		(net "M_B_CPU1_SA_DQS_DN<9>")
	)
	(segment
		(start 51.089814 -274.666964)
		(end 51.08956 -274.66671)
		(width 0.20066)
		(layer "F.Cu")
		(net "M_B_CPU1_SA_DQS_DN<9>")
	)
	(segment
		(start 51.08956 -274.66671)
		(end 49.959514 -274.66671)
		(width 0.20066)
		(layer "F.Cu")
		(net "M_B_CPU1_SA_DQS_DN<9>")
	)
	(segment
		(start 47.868332 -273.980656)
		(end 48.504348 -274.405598)
		(width 0.20066)
		(layer "F.Cu")
		(net "M_B_CPU1_SA_DQS_DN<9>")
	)
	(segment
		(start 44.044108 -273.983196)
		(end 44.283884 -273.983196)
		(width 0.20066)
		(layer "F.Cu")
		(net "M_B_CPU1_SA_DQS_DN<9>")
	)
	(segment
		(start 42.415714 -274.66671)
		(end 42.887392 -274.66671)
		(width 0.20066)
		(layer "F.Cu")
		(net "M_B_CPU1_SA_DQS_DN<9>")
	)
	(segment
		(start 44.982892 -274.241768)
		(end 47.060358 -274.241768)
		(width 0.1016)
		(layer "F.Cu")
		(net "M_B_CPU1_SA_DQS_DN<9>")
	)
	(segment
		(start 44.552108 -274.25142)
		(end 44.735242 -274.25142)
		(width 0.20066)
		(layer "F.Cu")
		(net "M_B_CPU1_SA_DQS_DN<9>")
	)
	(segment
		(start 42.887392 -274.66671)
		(end 43.148504 -274.405598)
		(width 0.20066)
		(layer "F.Cu")
		(net "M_B_CPU1_SA_DQS_DN<9>")
	)
	(segment
		(start 44.283884 -273.983196)
		(end 44.552108 -274.25142)
		(width 0.20066)
		(layer "F.Cu")
		(net "M_B_CPU1_SA_DQS_DN<9>")
	)
	(segment
		(start 47.46371 -273.980656)
		(end 47.868332 -273.980656)
		(width 0.20066)
		(layer "F.Cu")
		(net "M_B_CPU1_SA_DQS_DN<9>")
	)
	(segment
		(start 48.504348 -274.405598)
		(end 49.207928 -274.405598)
		(width 0.20066)
		(layer "F.Cu")
		(net "M_B_CPU1_SA_DQS_DN<9>")
	)
	(segment
		(start 43.148504 -274.405598)
		(end 43.621706 -274.405598)
		(width 0.20066)
		(layer "F.Cu")
		(net "M_B_CPU1_SA_DQS_DN<9>")
	)
	(segment
		(start 44.735242 -274.25142)
		(end 44.744894 -274.241768)
		(width 0.101854)
		(layer "F.Cu")
		(net "M_B_CPU1_SA_DQS_DN<9>")
	)
	(segment
		(start 43.621706 -274.405598)
		(end 44.044108 -273.983196)
		(width 0.20066)
		(layer "F.Cu")
		(net "M_B_CPU1_SA_DQS_DN<9>")
	)
	(segment
		(start 81.1657 -262.224012)
		(end 81.046066 -262.343646)
		(width 0.088646)
		(layer "In2.Cu")
		(net "M_B_CPU1_SA_DQS_DN<9>")
	)
	(segment
		(start 65.817242 -271.756632)
		(end 65.800986 -271.756632)
		(width 0.16002)
		(layer "In2.Cu")
		(net "M_B_CPU1_SA_DQS_DN<9>")
	)
	(segment
		(start 64.321436 -271.728438)
		(end 64.293242 -271.756632)
		(width 0.16002)
		(layer "In2.Cu")
		(net "M_B_CPU1_SA_DQS_DN<9>")
	)
	(segment
		(start 51.24704 -274.307046)
		(end 51.141122 -274.412964)
		(width 0.18288)
		(layer "In2.Cu")
		(net "M_B_CPU1_SA_DQS_DN<9>")
	)
	(segment
		(start 56.870092 -273.33575)
		(end 56.777636 -273.428206)
		(width 0.18288)
		(layer "In2.Cu")
		(net "M_B_CPU1_SA_DQS_DN<9>")
	)
	(segment
		(start 58.473086 -273.6723)
		(end 58.473086 -273.656044)
		(width 0.16002)
		(layer "In2.Cu")
		(net "M_B_CPU1_SA_DQS_DN<9>")
	)
	(segment
		(start 52.769262 -274.18665)
		(end 52.677568 -274.278344)
		(width 0.18288)
		(layer "In2.Cu")
		(net "M_B_CPU1_SA_DQS_DN<9>")
	)
	(segment
		(start 59.177682 -273.971512)
		(end 58.772298 -273.971512)
		(width 0.18288)
		(layer "In2.Cu")
		(net "M_B_CPU1_SA_DQS_DN<9>")
	)
	(segment
		(start 64.077342 -271.956276)
		(end 64.077342 -271.972532)
		(width 0.16002)
		(layer "In2.Cu")
		(net "M_B_CPU1_SA_DQS_DN<9>")
	)
	(segment
		(start 90.447876 -260.430772)
		(end 90.505026 -260.373622)
		(width 0.088646)
		(layer "In2.Cu")
		(net "M_B_CPU1_SA_DQS_DN<9>")
	)
	(segment
		(start 90.331036 -260.111494)
		(end 90.32367 -260.107176)
		(width 0.088646)
		(layer "In2.Cu")
		(net "M_B_CPU1_SA_DQS_DN<9>")
	)
	(segment
		(start 62.015878 -273.450304)
		(end 62.00013 -273.450304)
		(width 0.16002)
		(layer "In2.Cu")
		(net "M_B_CPU1_SA_DQS_DN<9>")
	)
	(segment
		(start 52.677568 -274.278344)
		(end 52.649374 -274.306538)
		(width 0.16002)
		(layer "In2.Cu")
		(net "M_B_CPU1_SA_DQS_DN<9>")
	)
	(segment
		(start 81.787238 -262.224012)
		(end 81.1657 -262.224012)
		(width 0.088646)
		(layer "In2.Cu")
		(net "M_B_CPU1_SA_DQS_DN<9>")
	)
	(segment
		(start 61.49467 -273.971512)
		(end 60.07481 -273.971512)
		(width 0.18288)
		(layer "In2.Cu")
		(net "M_B_CPU1_SA_DQS_DN<9>")
	)
	(segment
		(start 58.136536 -273.33575)
		(end 56.870092 -273.33575)
		(width 0.18288)
		(layer "In2.Cu")
		(net "M_B_CPU1_SA_DQS_DN<9>")
	)
	(segment
		(start 64.276986 -271.756632)
		(end 64.077342 -271.956276)
		(width 0.16002)
		(layer "In2.Cu")
		(net "M_B_CPU1_SA_DQS_DN<9>")
	)
	(segment
		(start 54.03723 -274.18665)
		(end 52.769262 -274.18665)
		(width 0.18288)
		(layer "In2.Cu")
		(net "M_B_CPU1_SA_DQS_DN<9>")
	)
	(segment
		(start 58.473086 -273.656044)
		(end 58.273442 -273.4564)
		(width 0.16002)
		(layer "In2.Cu")
		(net "M_B_CPU1_SA_DQS_DN<9>")
	)
	(segment
		(start 54.373018 -274.522438)
		(end 54.373018 -274.506182)
		(width 0.16002)
		(layer "In2.Cu")
		(net "M_B_CPU1_SA_DQS_DN<9>")
	)
	(segment
		(start 51.141122 -274.412964)
		(end 51.089814 -274.536916)
		(width 0.18288)
		(layer "In2.Cu")
		(net "M_B_CPU1_SA_DQS_DN<9>")
	)
	(segment
		(start 52.279042 -274.67687)
		(end 51.80203 -274.67687)
		(width 0.18288)
		(layer "In2.Cu")
		(net "M_B_CPU1_SA_DQS_DN<9>")
	)
	(segment
		(start 78.53807 -262.343646)
		(end 77.266038 -263.615678)
		(width 0.18288)
		(layer "In2.Cu")
		(net "M_B_CPU1_SA_DQS_DN<9>")
	)
	(segment
		(start 90.134948 -260.430772)
		(end 90.447876 -260.430772)
		(width 0.088646)
		(layer "In2.Cu")
		(net "M_B_CPU1_SA_DQS_DN<9>")
	)
	(segment
		(start 61.799978 -273.650456)
		(end 61.799978 -273.666204)
		(width 0.16002)
		(layer "In2.Cu")
		(net "M_B_CPU1_SA_DQS_DN<9>")
	)
	(segment
		(start 54.401212 -274.550632)
		(end 54.373018 -274.522438)
		(width 0.16002)
		(layer "In2.Cu")
		(net "M_B_CPU1_SA_DQS_DN<9>")
	)
	(segment
		(start 62.00013 -273.450304)
		(end 61.799978 -273.650456)
		(width 0.16002)
		(layer "In2.Cu")
		(net "M_B_CPU1_SA_DQS_DN<9>")
	)
	(segment
		(start 90.32367 -260.107176)
		(end 90.322146 -260.106414)
		(width 0.088646)
		(layer "In2.Cu")
		(net "M_B_CPU1_SA_DQS_DN<9>")
	)
	(segment
		(start 52.649374 -274.306538)
		(end 52.633118 -274.306538)
		(width 0.16002)
		(layer "In2.Cu")
		(net "M_B_CPU1_SA_DQS_DN<9>")
	)
	(segment
		(start 51.432206 -274.307046)
		(end 51.24704 -274.307046)
		(width 0.18288)
		(layer "In2.Cu")
		(net "M_B_CPU1_SA_DQS_DN<9>")
	)
	(segment
		(start 62.691772 -272.77441)
		(end 62.044072 -273.42211)
		(width 0.18288)
		(layer "In2.Cu")
		(net "M_B_CPU1_SA_DQS_DN<9>")
	)
	(segment
		(start 52.433474 -274.522438)
		(end 52.40528 -274.550632)
		(width 0.16002)
		(layer "In2.Cu")
		(net "M_B_CPU1_SA_DQS_DN<9>")
	)
	(segment
		(start 65.800986 -271.756632)
		(end 65.772792 -271.728438)
		(width 0.16002)
		(layer "In2.Cu")
		(net "M_B_CPU1_SA_DQS_DN<9>")
	)
	(segment
		(start 61.799978 -273.666204)
		(end 61.771784 -273.694398)
		(width 0.16002)
		(layer "In2.Cu")
		(net "M_B_CPU1_SA_DQS_DN<9>")
	)
	(segment
		(start 66.016886 -271.956276)
		(end 65.817242 -271.756632)
		(width 0.16002)
		(layer "In2.Cu")
		(net "M_B_CPU1_SA_DQS_DN<9>")
	)
	(segment
		(start 66.839592 -272.19529)
		(end 66.239644 -272.19529)
		(width 0.18288)
		(layer "In2.Cu")
		(net "M_B_CPU1_SA_DQS_DN<9>")
	)
	(segment
		(start 54.157118 -274.306538)
		(end 54.128924 -274.278344)
		(width 0.16002)
		(layer "In2.Cu")
		(net "M_B_CPU1_SA_DQS_DN<9>")
	)
	(segment
		(start 64.293242 -271.756632)
		(end 64.276986 -271.756632)
		(width 0.16002)
		(layer "In2.Cu")
		(net "M_B_CPU1_SA_DQS_DN<9>")
	)
	(segment
		(start 66.239644 -272.19529)
		(end 66.04508 -272.000726)
		(width 0.18288)
		(layer "In2.Cu")
		(net "M_B_CPU1_SA_DQS_DN<9>")
	)
	(segment
		(start 66.04508 -272.000726)
		(end 66.016886 -271.972532)
		(width 0.16002)
		(layer "In2.Cu")
		(net "M_B_CPU1_SA_DQS_DN<9>")
	)
	(segment
		(start 83.829144 -260.182106)
		(end 81.787238 -262.224012)
		(width 0.088646)
		(layer "In2.Cu")
		(net "M_B_CPU1_SA_DQS_DN<9>")
	)
	(segment
		(start 58.273442 -273.4564)
		(end 58.257186 -273.4564)
		(width 0.16002)
		(layer "In2.Cu")
		(net "M_B_CPU1_SA_DQS_DN<9>")
	)
	(segment
		(start 88.452706 -260.11251)
		(end 88.442292 -260.106414)
		(width 0.088646)
		(layer "In2.Cu")
		(net "M_B_CPU1_SA_DQS_DN<9>")
	)
	(segment
		(start 56.533542 -273.6723)
		(end 56.505348 -273.700494)
		(width 0.16002)
		(layer "In2.Cu")
		(net "M_B_CPU1_SA_DQS_DN<9>")
	)
	(segment
		(start 61.771784 -273.694398)
		(end 61.49467 -273.971512)
		(width 0.18288)
		(layer "In2.Cu")
		(net "M_B_CPU1_SA_DQS_DN<9>")
	)
	(segment
		(start 56.733186 -273.4564)
		(end 56.533542 -273.656044)
		(width 0.16002)
		(layer "In2.Cu")
		(net "M_B_CPU1_SA_DQS_DN<9>")
	)
	(segment
		(start 56.533542 -273.656044)
		(end 56.533542 -273.6723)
		(width 0.16002)
		(layer "In2.Cu")
		(net "M_B_CPU1_SA_DQS_DN<9>")
	)
	(segment
		(start 52.40528 -274.550632)
		(end 52.279042 -274.67687)
		(width 0.18288)
		(layer "In2.Cu")
		(net "M_B_CPU1_SA_DQS_DN<9>")
	)
	(segment
		(start 63.275464 -272.77441)
		(end 62.691772 -272.77441)
		(width 0.18288)
		(layer "In2.Cu")
		(net "M_B_CPU1_SA_DQS_DN<9>")
	)
	(segment
		(start 55.122572 -274.73783)
		(end 54.58841 -274.73783)
		(width 0.18288)
		(layer "In2.Cu")
		(net "M_B_CPU1_SA_DQS_DN<9>")
	)
	(segment
		(start 66.016886 -271.972532)
		(end 66.016886 -271.956276)
		(width 0.16002)
		(layer "In2.Cu")
		(net "M_B_CPU1_SA_DQS_DN<9>")
	)
	(segment
		(start 89.397078 -260.11505)
		(end 89.382346 -260.106414)
		(width 0.088646)
		(layer "In2.Cu")
		(net "M_B_CPU1_SA_DQS_DN<9>")
	)
	(segment
		(start 54.373018 -274.506182)
		(end 54.173374 -274.306538)
		(width 0.16002)
		(layer "In2.Cu")
		(net "M_B_CPU1_SA_DQS_DN<9>")
	)
	(segment
		(start 56.505348 -273.700494)
		(end 56.018938 -274.186904)
		(width 0.18288)
		(layer "In2.Cu")
		(net "M_B_CPU1_SA_DQS_DN<9>")
	)
	(segment
		(start 52.633118 -274.306538)
		(end 52.433474 -274.506182)
		(width 0.16002)
		(layer "In2.Cu")
		(net "M_B_CPU1_SA_DQS_DN<9>")
	)
	(segment
		(start 64.049148 -272.000726)
		(end 63.275464 -272.77441)
		(width 0.18288)
		(layer "In2.Cu")
		(net "M_B_CPU1_SA_DQS_DN<9>")
	)
	(segment
		(start 65.772792 -271.728438)
		(end 65.680336 -271.635982)
		(width 0.18288)
		(layer "In2.Cu")
		(net "M_B_CPU1_SA_DQS_DN<9>")
	)
	(segment
		(start 64.413892 -271.635982)
		(end 64.321436 -271.728438)
		(width 0.18288)
		(layer "In2.Cu")
		(net "M_B_CPU1_SA_DQS_DN<9>")
	)
	(segment
		(start 62.044072 -273.42211)
		(end 62.015878 -273.450304)
		(width 0.16002)
		(layer "In2.Cu")
		(net "M_B_CPU1_SA_DQS_DN<9>")
	)
	(segment
		(start 55.673498 -274.186904)
		(end 55.122572 -274.73783)
		(width 0.18288)
		(layer "In2.Cu")
		(net "M_B_CPU1_SA_DQS_DN<9>")
	)
	(segment
		(start 74.111104 -264.926826)
		(end 66.839592 -272.19529)
		(width 0.18288)
		(layer "In2.Cu")
		(net "M_B_CPU1_SA_DQS_DN<9>")
	)
	(segment
		(start 58.50128 -273.700494)
		(end 58.473086 -273.6723)
		(width 0.16002)
		(layer "In2.Cu")
		(net "M_B_CPU1_SA_DQS_DN<9>")
	)
	(segment
		(start 58.257186 -273.4564)
		(end 58.228992 -273.428206)
		(width 0.16002)
		(layer "In2.Cu")
		(net "M_B_CPU1_SA_DQS_DN<9>")
	)
	(segment
		(start 52.433474 -274.506182)
		(end 52.433474 -274.522438)
		(width 0.16002)
		(layer "In2.Cu")
		(net "M_B_CPU1_SA_DQS_DN<9>")
	)
	(segment
		(start 59.449462 -274.243292)
		(end 59.177682 -273.971512)
		(width 0.18288)
		(layer "In2.Cu")
		(net "M_B_CPU1_SA_DQS_DN<9>")
	)
	(segment
		(start 81.022698 -262.343646)
		(end 78.53807 -262.343646)
		(width 0.18288)
		(layer "In2.Cu")
		(net "M_B_CPU1_SA_DQS_DN<9>")
	)
	(segment
		(start 58.228992 -273.428206)
		(end 58.136536 -273.33575)
		(width 0.18288)
		(layer "In2.Cu")
		(net "M_B_CPU1_SA_DQS_DN<9>")
	)
	(segment
		(start 54.173374 -274.306538)
		(end 54.157118 -274.306538)
		(width 0.16002)
		(layer "In2.Cu")
		(net "M_B_CPU1_SA_DQS_DN<9>")
	)
	(segment
		(start 81.046066 -262.343646)
		(end 81.022698 -262.343646)
		(width 0.088646)
		(layer "In2.Cu")
		(net "M_B_CPU1_SA_DQS_DN<9>")
	)
	(segment
		(start 56.018938 -274.186904)
		(end 55.673498 -274.186904)
		(width 0.18288)
		(layer "In2.Cu")
		(net "M_B_CPU1_SA_DQS_DN<9>")
	)
	(segment
		(start 58.772298 -273.971512)
		(end 58.50128 -273.700494)
		(width 0.18288)
		(layer "In2.Cu")
		(net "M_B_CPU1_SA_DQS_DN<9>")
	)
	(segment
		(start 77.266038 -263.615678)
		(end 74.111104 -264.926826)
		(width 0.18288)
		(layer "In2.Cu")
		(net "M_B_CPU1_SA_DQS_DN<9>")
	)
	(segment
		(start 54.128924 -274.278344)
		(end 54.03723 -274.18665)
		(width 0.18288)
		(layer "In2.Cu")
		(net "M_B_CPU1_SA_DQS_DN<9>")
	)
	(segment
		(start 84.025994 -260.182106)
		(end 83.829144 -260.182106)
		(width 0.088646)
		(layer "In2.Cu")
		(net "M_B_CPU1_SA_DQS_DN<9>")
	)
	(segment
		(start 56.777636 -273.428206)
		(end 56.749442 -273.4564)
		(width 0.16002)
		(layer "In2.Cu")
		(net "M_B_CPU1_SA_DQS_DN<9>")
	)
	(segment
		(start 54.58841 -274.73783)
		(end 54.401212 -274.550632)
		(width 0.18288)
		(layer "In2.Cu")
		(net "M_B_CPU1_SA_DQS_DN<9>")
	)
	(segment
		(start 60.07481 -273.971512)
		(end 59.80303 -274.243292)
		(width 0.18288)
		(layer "In2.Cu")
		(net "M_B_CPU1_SA_DQS_DN<9>")
	)
	(segment
		(start 56.749442 -273.4564)
		(end 56.733186 -273.4564)
		(width 0.16002)
		(layer "In2.Cu")
		(net "M_B_CPU1_SA_DQS_DN<9>")
	)
	(segment
		(start 51.089814 -274.536916)
		(end 51.089814 -274.666964)
		(width 0.18288)
		(layer "In2.Cu")
		(net "M_B_CPU1_SA_DQS_DN<9>")
	)
	(segment
		(start 65.680336 -271.635982)
		(end 64.413892 -271.635982)
		(width 0.18288)
		(layer "In2.Cu")
		(net "M_B_CPU1_SA_DQS_DN<9>")
	)
	(segment
		(start 64.077342 -271.972532)
		(end 64.049148 -272.000726)
		(width 0.16002)
		(layer "In2.Cu")
		(net "M_B_CPU1_SA_DQS_DN<9>")
	)
	(segment
		(start 51.80203 -274.67687)
		(end 51.432206 -274.307046)
		(width 0.18288)
		(layer "In2.Cu")
		(net "M_B_CPU1_SA_DQS_DN<9>")
	)
	(segment
		(start 59.80303 -274.243292)
		(end 59.449462 -274.243292)
		(width 0.18288)
		(layer "In2.Cu")
		(net "M_B_CPU1_SA_DQS_DN<9>")
	)
	(arc
		(start 85.248496 -260.106414)
		(mid 84.965794 -260.18219)
		(end 84.683092 -260.106414)
		(width 0.088646)
		(layer "In2.Cu")
		(net "M_B_CPU1_SA_DQS_DN<9>")
	)
	(arc
		(start 84.683092 -260.106414)
		(mid 84.495894 -260.056271)
		(end 84.308696 -260.106414)
		(width 0.088646)
		(layer "In2.Cu")
		(net "M_B_CPU1_SA_DQS_DN<9>")
	)
	(arc
		(start 86.188296 -260.106414)
		(mid 85.905594 -260.18219)
		(end 85.622892 -260.106414)
		(width 0.088646)
		(layer "In2.Cu")
		(net "M_B_CPU1_SA_DQS_DN<9>")
	)
	(arc
		(start 85.622892 -260.106414)
		(mid 85.435694 -260.056271)
		(end 85.248496 -260.106414)
		(width 0.088646)
		(layer "In2.Cu")
		(net "M_B_CPU1_SA_DQS_DN<9>")
	)
	(arc
		(start 89.00795 -260.106414)
		(mid 88.731137 -260.182284)
		(end 88.452706 -260.11251)
		(width 0.088646)
		(layer "In2.Cu")
		(net "M_B_CPU1_SA_DQS_DN<9>")
	)
	(arc
		(start 89.94775 -260.106414)
		(mid 89.673551 -260.182249)
		(end 89.397078 -260.11505)
		(width 0.088646)
		(layer "In2.Cu")
		(net "M_B_CPU1_SA_DQS_DN<9>")
	)
	(arc
		(start 89.382346 -260.106414)
		(mid 89.195148 -260.056271)
		(end 89.00795 -260.106414)
		(width 0.088646)
		(layer "In2.Cu")
		(net "M_B_CPU1_SA_DQS_DN<9>")
	)
	(arc
		(start 87.128096 -260.106414)
		(mid 86.845394 -260.18219)
		(end 86.562692 -260.106414)
		(width 0.088646)
		(layer "In2.Cu")
		(net "M_B_CPU1_SA_DQS_DN<9>")
	)
	(arc
		(start 90.322146 -260.106414)
		(mid 90.134948 -260.056271)
		(end 89.94775 -260.106414)
		(width 0.088646)
		(layer "In2.Cu")
		(net "M_B_CPU1_SA_DQS_DN<9>")
	)
	(arc
		(start 87.502492 -260.106414)
		(mid 87.315294 -260.056271)
		(end 87.128096 -260.106414)
		(width 0.088646)
		(layer "In2.Cu")
		(net "M_B_CPU1_SA_DQS_DN<9>")
	)
	(arc
		(start 88.442292 -260.106414)
		(mid 88.255094 -260.056271)
		(end 88.067896 -260.106414)
		(width 0.088646)
		(layer "In2.Cu")
		(net "M_B_CPU1_SA_DQS_DN<9>")
	)
	(arc
		(start 88.067896 -260.106414)
		(mid 87.785194 -260.18219)
		(end 87.502492 -260.106414)
		(width 0.088646)
		(layer "In2.Cu")
		(net "M_B_CPU1_SA_DQS_DN<9>")
	)
	(arc
		(start 90.505026 -260.373622)
		(mid 90.446907 -260.223381)
		(end 90.331036 -260.111494)
		(width 0.088646)
		(layer "In2.Cu")
		(net "M_B_CPU1_SA_DQS_DN<9>")
	)
	(arc
		(start 84.308696 -260.106414)
		(mid 84.17233 -260.162892)
		(end 84.025994 -260.182106)
		(width 0.088646)
		(layer "In2.Cu")
		(net "M_B_CPU1_SA_DQS_DN<9>")
	)
	(arc
		(start 86.562692 -260.106414)
		(mid 86.375494 -260.056271)
		(end 86.188296 -260.106414)
		(width 0.088646)
		(layer "In2.Cu")
		(net "M_B_CPU1_SA_DQS_DN<9>")
	)
	(segment
		(start 47.060358 -283.591762)
		(end 47.202598 -283.591762)
		(width 0.20066)
		(layer "F.Cu")
		(net "M_B_CPU1_SA_DQS_DN<8>")
	)
	(segment
		(start 94.364048 -262.336534)
		(end 94.364048 -262.87222)
		(width 0.20066)
		(layer "F.Cu")
		(net "M_B_CPU1_SA_DQS_DN<8>")
	)
	(segment
		(start 42.887392 -284.016704)
		(end 43.148504 -283.755592)
		(width 0.20066)
		(layer "F.Cu")
		(net "M_B_CPU1_SA_DQS_DN<8>")
	)
	(segment
		(start 49.207928 -283.755592)
		(end 49.46904 -284.016704)
		(width 0.20066)
		(layer "F.Cu")
		(net "M_B_CPU1_SA_DQS_DN<8>")
	)
	(segment
		(start 51.089814 -284.016958)
		(end 51.08956 -284.016704)
		(width 0.20066)
		(layer "F.Cu")
		(net "M_B_CPU1_SA_DQS_DN<8>")
	)
	(segment
		(start 44.744894 -283.591762)
		(end 44.982892 -283.591762)
		(width 0.101854)
		(layer "F.Cu")
		(net "M_B_CPU1_SA_DQS_DN<8>")
	)
	(segment
		(start 43.621706 -283.755592)
		(end 44.044108 -283.33319)
		(width 0.20066)
		(layer "F.Cu")
		(net "M_B_CPU1_SA_DQS_DN<8>")
	)
	(segment
		(start 44.982892 -283.591762)
		(end 47.060358 -283.591762)
		(width 0.1016)
		(layer "F.Cu")
		(net "M_B_CPU1_SA_DQS_DN<8>")
	)
	(segment
		(start 44.044108 -283.33319)
		(end 44.283884 -283.33319)
		(width 0.20066)
		(layer "F.Cu")
		(net "M_B_CPU1_SA_DQS_DN<8>")
	)
	(segment
		(start 51.08956 -284.016704)
		(end 49.959514 -284.016704)
		(width 0.20066)
		(layer "F.Cu")
		(net "M_B_CPU1_SA_DQS_DN<8>")
	)
	(segment
		(start 43.148504 -283.755592)
		(end 43.621706 -283.755592)
		(width 0.20066)
		(layer "F.Cu")
		(net "M_B_CPU1_SA_DQS_DN<8>")
	)
	(segment
		(start 47.868332 -283.33065)
		(end 48.504348 -283.755592)
		(width 0.20066)
		(layer "F.Cu")
		(net "M_B_CPU1_SA_DQS_DN<8>")
	)
	(segment
		(start 44.735242 -283.601414)
		(end 44.744894 -283.591762)
		(width 0.101854)
		(layer "F.Cu")
		(net "M_B_CPU1_SA_DQS_DN<8>")
	)
	(segment
		(start 49.46904 -284.016704)
		(end 49.959514 -284.016704)
		(width 0.20066)
		(layer "F.Cu")
		(net "M_B_CPU1_SA_DQS_DN<8>")
	)
	(segment
		(start 47.202598 -283.591762)
		(end 47.46371 -283.33065)
		(width 0.20066)
		(layer "F.Cu")
		(net "M_B_CPU1_SA_DQS_DN<8>")
	)
	(segment
		(start 44.283884 -283.33319)
		(end 44.552108 -283.601414)
		(width 0.20066)
		(layer "F.Cu")
		(net "M_B_CPU1_SA_DQS_DN<8>")
	)
	(segment
		(start 42.415714 -284.016704)
		(end 42.887392 -284.016704)
		(width 0.20066)
		(layer "F.Cu")
		(net "M_B_CPU1_SA_DQS_DN<8>")
	)
	(segment
		(start 48.504348 -283.755592)
		(end 49.207928 -283.755592)
		(width 0.20066)
		(layer "F.Cu")
		(net "M_B_CPU1_SA_DQS_DN<8>")
	)
	(segment
		(start 94.364048 -262.87222)
		(end 94.363794 -262.872474)
		(width 0.20066)
		(layer "F.Cu")
		(net "M_B_CPU1_SA_DQS_DN<8>")
	)
	(segment
		(start 47.46371 -283.33065)
		(end 47.868332 -283.33065)
		(width 0.20066)
		(layer "F.Cu")
		(net "M_B_CPU1_SA_DQS_DN<8>")
	)
	(segment
		(start 44.552108 -283.601414)
		(end 44.735242 -283.601414)
		(width 0.20066)
		(layer "F.Cu")
		(net "M_B_CPU1_SA_DQS_DN<8>")
	)
	(segment
		(start 83.37931 -262.623808)
		(end 83.292442 -262.710676)
		(width 0.088646)
		(layer "In4.Cu")
		(net "M_B_CPU1_SA_DQS_DN<8>")
	)
	(segment
		(start 79.731108 -262.77062)
		(end 77.590904 -263.657588)
		(width 0.18288)
		(layer "In4.Cu")
		(net "M_B_CPU1_SA_DQS_DN<8>")
	)
	(segment
		(start 51.869848 -283.901642)
		(end 51.715162 -283.746956)
		(width 0.18288)
		(layer "In4.Cu")
		(net "M_B_CPU1_SA_DQS_DN<8>")
	)
	(segment
		(start 53.997606 -282.575508)
		(end 52.828698 -283.744416)
		(width 0.18288)
		(layer "In4.Cu")
		(net "M_B_CPU1_SA_DQS_DN<8>")
	)
	(segment
		(start 93.107002 -263.101074)
		(end 92.942664 -262.936736)
		(width 0.088646)
		(layer "In4.Cu")
		(net "M_B_CPU1_SA_DQS_DN<8>")
	)
	(segment
		(start 82.812128 -262.77062)
		(end 82.783934 -262.77062)
		(width 0.088646)
		(layer "In4.Cu")
		(net "M_B_CPU1_SA_DQS_DN<8>")
	)
	(segment
		(start 55.119016 -281.925268)
		(end 54.80177 -282.242514)
		(width 0.18288)
		(layer "In4.Cu")
		(net "M_B_CPU1_SA_DQS_DN<8>")
	)
	(segment
		(start 83.292442 -262.710676)
		(end 82.872072 -262.710676)
		(width 0.088646)
		(layer "In4.Cu")
		(net "M_B_CPU1_SA_DQS_DN<8>")
	)
	(segment
		(start 54.80177 -282.242514)
		(end 53.997606 -282.575508)
		(width 0.18288)
		(layer "In4.Cu")
		(net "M_B_CPU1_SA_DQS_DN<8>")
	)
	(segment
		(start 51.715162 -283.746956)
		(end 51.359816 -283.746956)
		(width 0.18288)
		(layer "In4.Cu")
		(net "M_B_CPU1_SA_DQS_DN<8>")
	)
	(segment
		(start 67.96151 -273.286982)
		(end 63.810642 -275.006054)
		(width 0.18288)
		(layer "In4.Cu")
		(net "M_B_CPU1_SA_DQS_DN<8>")
	)
	(segment
		(start 88.917018 -262.550656)
		(end 88.912192 -262.548116)
		(width 0.088646)
		(layer "In4.Cu")
		(net "M_B_CPU1_SA_DQS_DN<8>")
	)
	(segment
		(start 52.447698 -283.901642)
		(end 51.869848 -283.901642)
		(width 0.18288)
		(layer "In4.Cu")
		(net "M_B_CPU1_SA_DQS_DN<8>")
	)
	(segment
		(start 61.764926 -277.586694)
		(end 60.26658 -279.08504)
		(width 0.18288)
		(layer "In4.Cu")
		(net "M_B_CPU1_SA_DQS_DN<8>")
	)
	(segment
		(start 63.810642 -275.006054)
		(end 63.59398 -275.222716)
		(width 0.18288)
		(layer "In4.Cu")
		(net "M_B_CPU1_SA_DQS_DN<8>")
	)
	(segment
		(start 77.590904 -263.657588)
		(end 67.96151 -273.286982)
		(width 0.18288)
		(layer "In4.Cu")
		(net "M_B_CPU1_SA_DQS_DN<8>")
	)
	(segment
		(start 93.992954 -262.973058)
		(end 93.615764 -263.194292)
		(width 0.088646)
		(layer "In4.Cu")
		(net "M_B_CPU1_SA_DQS_DN<8>")
	)
	(segment
		(start 58.32475 -279.889458)
		(end 56.433466 -279.889458)
		(width 0.18288)
		(layer "In4.Cu")
		(net "M_B_CPU1_SA_DQS_DN<8>")
	)
	(segment
		(start 55.630064 -280.69286)
		(end 55.119016 -281.925268)
		(width 0.18288)
		(layer "In4.Cu")
		(net "M_B_CPU1_SA_DQS_DN<8>")
	)
	(segment
		(start 83.838796 -262.548116)
		(end 83.838542 -262.547862)
		(width 0.088646)
		(layer "In4.Cu")
		(net "M_B_CPU1_SA_DQS_DN<8>")
	)
	(segment
		(start 82.783934 -262.77062)
		(end 79.731108 -262.77062)
		(width 0.18288)
		(layer "In4.Cu")
		(net "M_B_CPU1_SA_DQS_DN<8>")
	)
	(segment
		(start 89.855802 -262.550148)
		(end 89.852246 -262.548116)
		(width 0.088646)
		(layer "In4.Cu")
		(net "M_B_CPU1_SA_DQS_DN<8>")
	)
	(segment
		(start 62.474348 -277.292816)
		(end 61.764926 -277.586694)
		(width 0.18288)
		(layer "In4.Cu")
		(net "M_B_CPU1_SA_DQS_DN<8>")
	)
	(segment
		(start 90.797888 -262.551418)
		(end 90.786204 -262.544814)
		(width 0.088646)
		(layer "In4.Cu")
		(net "M_B_CPU1_SA_DQS_DN<8>")
	)
	(segment
		(start 56.433466 -279.889458)
		(end 55.630064 -280.69286)
		(width 0.18288)
		(layer "In4.Cu")
		(net "M_B_CPU1_SA_DQS_DN<8>")
	)
	(segment
		(start 63.59398 -275.222716)
		(end 62.921388 -276.845776)
		(width 0.18288)
		(layer "In4.Cu")
		(net "M_B_CPU1_SA_DQS_DN<8>")
	)
	(segment
		(start 82.872072 -262.710676)
		(end 82.812128 -262.77062)
		(width 0.088646)
		(layer "In4.Cu")
		(net "M_B_CPU1_SA_DQS_DN<8>")
	)
	(segment
		(start 92.739464 -262.58647)
		(end 92.665804 -262.544814)
		(width 0.088646)
		(layer "In4.Cu")
		(net "M_B_CPU1_SA_DQS_DN<8>")
	)
	(segment
		(start 60.26658 -279.08504)
		(end 58.32475 -279.889458)
		(width 0.18288)
		(layer "In4.Cu")
		(net "M_B_CPU1_SA_DQS_DN<8>")
	)
	(segment
		(start 83.556348 -262.623808)
		(end 83.37931 -262.623808)
		(width 0.088646)
		(layer "In4.Cu")
		(net "M_B_CPU1_SA_DQS_DN<8>")
	)
	(segment
		(start 51.359816 -283.746956)
		(end 51.089814 -284.016958)
		(width 0.18288)
		(layer "In4.Cu")
		(net "M_B_CPU1_SA_DQS_DN<8>")
	)
	(segment
		(start 62.921388 -276.845776)
		(end 62.474348 -277.292816)
		(width 0.18288)
		(layer "In4.Cu")
		(net "M_B_CPU1_SA_DQS_DN<8>")
	)
	(segment
		(start 52.828698 -283.744416)
		(end 52.447698 -283.901642)
		(width 0.18288)
		(layer "In4.Cu")
		(net "M_B_CPU1_SA_DQS_DN<8>")
	)
	(segment
		(start 91.737688 -262.551418)
		(end 91.726004 -262.544814)
		(width 0.088646)
		(layer "In4.Cu")
		(net "M_B_CPU1_SA_DQS_DN<8>")
	)
	(arc
		(start 85.152992 -262.548116)
		(mid 84.965794 -262.497973)
		(end 84.778596 -262.548116)
		(width 0.088646)
		(layer "In4.Cu")
		(net "M_B_CPU1_SA_DQS_DN<8>")
	)
	(arc
		(start 87.597996 -262.548116)
		(mid 87.315294 -262.623892)
		(end 87.032592 -262.548116)
		(width 0.088646)
		(layer "In4.Cu")
		(net "M_B_CPU1_SA_DQS_DN<8>")
	)
	(arc
		(start 88.912192 -262.548116)
		(mid 88.724994 -262.497973)
		(end 88.537796 -262.548116)
		(width 0.088646)
		(layer "In4.Cu")
		(net "M_B_CPU1_SA_DQS_DN<8>")
	)
	(arc
		(start 90.786204 -262.544814)
		(mid 90.601349 -262.497864)
		(end 90.417396 -262.548116)
		(width 0.088646)
		(layer "In4.Cu")
		(net "M_B_CPU1_SA_DQS_DN<8>")
	)
	(arc
		(start 90.417396 -262.548116)
		(mid 90.136885 -262.623762)
		(end 89.855802 -262.550148)
		(width 0.088646)
		(layer "In4.Cu")
		(net "M_B_CPU1_SA_DQS_DN<8>")
	)
	(arc
		(start 93.615764 -263.194292)
		(mid 93.583965 -263.211167)
		(end 93.55074 -263.225026)
		(width 0.088646)
		(layer "In4.Cu")
		(net "M_B_CPU1_SA_DQS_DN<8>")
	)
	(arc
		(start 92.891864 -262.814054)
		(mid 92.861764 -262.722708)
		(end 92.808552 -262.642604)
		(width 0.088646)
		(layer "In4.Cu")
		(net "M_B_CPU1_SA_DQS_DN<8>")
	)
	(arc
		(start 92.808552 -262.642604)
		(mid 92.776386 -262.611607)
		(end 92.739464 -262.58647)
		(width 0.088646)
		(layer "In4.Cu")
		(net "M_B_CPU1_SA_DQS_DN<8>")
	)
	(arc
		(start 91.357196 -262.548116)
		(mid 91.077993 -262.623756)
		(end 90.797888 -262.551418)
		(width 0.088646)
		(layer "In4.Cu")
		(net "M_B_CPU1_SA_DQS_DN<8>")
	)
	(arc
		(start 92.942664 -262.936736)
		(mid 92.905054 -262.880449)
		(end 92.891864 -262.814054)
		(width 0.088646)
		(layer "In4.Cu")
		(net "M_B_CPU1_SA_DQS_DN<8>")
	)
	(arc
		(start 86.092792 -262.548116)
		(mid 85.905594 -262.497973)
		(end 85.718396 -262.548116)
		(width 0.088646)
		(layer "In4.Cu")
		(net "M_B_CPU1_SA_DQS_DN<8>")
	)
	(arc
		(start 83.838542 -262.547862)
		(mid 83.702443 -262.604411)
		(end 83.556348 -262.623808)
		(width 0.088646)
		(layer "In4.Cu")
		(net "M_B_CPU1_SA_DQS_DN<8>")
	)
	(arc
		(start 93.269562 -263.213596)
		(mid 93.183206 -263.164667)
		(end 93.107002 -263.101074)
		(width 0.088646)
		(layer "In4.Cu")
		(net "M_B_CPU1_SA_DQS_DN<8>")
	)
	(arc
		(start 87.972392 -262.548116)
		(mid 87.785194 -262.497973)
		(end 87.597996 -262.548116)
		(width 0.088646)
		(layer "In4.Cu")
		(net "M_B_CPU1_SA_DQS_DN<8>")
	)
	(arc
		(start 86.658196 -262.548116)
		(mid 86.375494 -262.623892)
		(end 86.092792 -262.548116)
		(width 0.088646)
		(layer "In4.Cu")
		(net "M_B_CPU1_SA_DQS_DN<8>")
	)
	(arc
		(start 91.726004 -262.544814)
		(mid 91.541149 -262.497864)
		(end 91.357196 -262.548116)
		(width 0.088646)
		(layer "In4.Cu")
		(net "M_B_CPU1_SA_DQS_DN<8>")
	)
	(arc
		(start 89.852246 -262.548116)
		(mid 89.664938 -262.497973)
		(end 89.477596 -262.548116)
		(width 0.088646)
		(layer "In4.Cu")
		(net "M_B_CPU1_SA_DQS_DN<8>")
	)
	(arc
		(start 93.55074 -263.225026)
		(mid 93.409037 -263.246722)
		(end 93.269562 -263.213596)
		(width 0.088646)
		(layer "In4.Cu")
		(net "M_B_CPU1_SA_DQS_DN<8>")
	)
	(arc
		(start 89.477596 -262.548116)
		(mid 89.197652 -262.62376)
		(end 88.917018 -262.550656)
		(width 0.088646)
		(layer "In4.Cu")
		(net "M_B_CPU1_SA_DQS_DN<8>")
	)
	(arc
		(start 87.032592 -262.548116)
		(mid 86.845394 -262.497973)
		(end 86.658196 -262.548116)
		(width 0.088646)
		(layer "In4.Cu")
		(net "M_B_CPU1_SA_DQS_DN<8>")
	)
	(arc
		(start 94.363794 -262.872474)
		(mid 94.171664 -262.898031)
		(end 93.992954 -262.973058)
		(width 0.088646)
		(layer "In4.Cu")
		(net "M_B_CPU1_SA_DQS_DN<8>")
	)
	(arc
		(start 92.665804 -262.544814)
		(mid 92.480949 -262.497864)
		(end 92.296996 -262.548116)
		(width 0.088646)
		(layer "In4.Cu")
		(net "M_B_CPU1_SA_DQS_DN<8>")
	)
	(arc
		(start 92.296996 -262.548116)
		(mid 92.017793 -262.623756)
		(end 91.737688 -262.551418)
		(width 0.088646)
		(layer "In4.Cu")
		(net "M_B_CPU1_SA_DQS_DN<8>")
	)
	(arc
		(start 88.537796 -262.548116)
		(mid 88.255094 -262.623892)
		(end 87.972392 -262.548116)
		(width 0.088646)
		(layer "In4.Cu")
		(net "M_B_CPU1_SA_DQS_DN<8>")
	)
	(arc
		(start 85.718396 -262.548116)
		(mid 85.435694 -262.623892)
		(end 85.152992 -262.548116)
		(width 0.088646)
		(layer "In4.Cu")
		(net "M_B_CPU1_SA_DQS_DN<8>")
	)
	(arc
		(start 84.778596 -262.548116)
		(mid 84.495894 -262.623892)
		(end 84.213192 -262.548116)
		(width 0.088646)
		(layer "In4.Cu")
		(net "M_B_CPU1_SA_DQS_DN<8>")
	)
	(arc
		(start 84.213192 -262.548116)
		(mid 84.025994 -262.497973)
		(end 83.838796 -262.548116)
		(width 0.088646)
		(layer "In4.Cu")
		(net "M_B_CPU1_SA_DQS_DN<8>")
	)
	(segment
		(start 42.887392 -293.366698)
		(end 43.148504 -293.105586)
		(width 0.20066)
		(layer "F.Cu")
		(net "M_B_CPU1_SA_DQS_DN<7>")
	)
	(segment
		(start 44.552108 -292.951408)
		(end 44.735242 -292.951408)
		(width 0.20066)
		(layer "F.Cu")
		(net "M_B_CPU1_SA_DQS_DN<7>")
	)
	(segment
		(start 43.621706 -293.105586)
		(end 44.044108 -292.683184)
		(width 0.20066)
		(layer "F.Cu")
		(net "M_B_CPU1_SA_DQS_DN<7>")
	)
	(segment
		(start 44.982892 -292.941756)
		(end 47.060358 -292.941756)
		(width 0.1016)
		(layer "F.Cu")
		(net "M_B_CPU1_SA_DQS_DN<7>")
	)
	(segment
		(start 49.46904 -293.366698)
		(end 49.959514 -293.366698)
		(width 0.20066)
		(layer "F.Cu")
		(net "M_B_CPU1_SA_DQS_DN<7>")
	)
	(segment
		(start 47.202598 -292.941756)
		(end 47.46371 -292.680644)
		(width 0.20066)
		(layer "F.Cu")
		(net "M_B_CPU1_SA_DQS_DN<7>")
	)
	(segment
		(start 44.746418 -292.941756)
		(end 44.982892 -292.941756)
		(width 0.101854)
		(layer "F.Cu")
		(net "M_B_CPU1_SA_DQS_DN<7>")
	)
	(segment
		(start 42.415714 -293.366698)
		(end 42.887392 -293.366698)
		(width 0.20066)
		(layer "F.Cu")
		(net "M_B_CPU1_SA_DQS_DN<7>")
	)
	(segment
		(start 44.283884 -292.683184)
		(end 44.552108 -292.951408)
		(width 0.20066)
		(layer "F.Cu")
		(net "M_B_CPU1_SA_DQS_DN<7>")
	)
	(segment
		(start 48.504348 -293.105586)
		(end 49.207928 -293.105586)
		(width 0.20066)
		(layer "F.Cu")
		(net "M_B_CPU1_SA_DQS_DN<7>")
	)
	(segment
		(start 49.207928 -293.105586)
		(end 49.46904 -293.366698)
		(width 0.20066)
		(layer "F.Cu")
		(net "M_B_CPU1_SA_DQS_DN<7>")
	)
	(segment
		(start 47.868332 -292.680644)
		(end 48.504348 -293.105586)
		(width 0.20066)
		(layer "F.Cu")
		(net "M_B_CPU1_SA_DQS_DN<7>")
	)
	(segment
		(start 44.735242 -292.951408)
		(end 44.736766 -292.951408)
		(width 0.101854)
		(layer "F.Cu")
		(net "M_B_CPU1_SA_DQS_DN<7>")
	)
	(segment
		(start 47.060358 -292.941756)
		(end 47.202598 -292.941756)
		(width 0.20066)
		(layer "F.Cu")
		(net "M_B_CPU1_SA_DQS_DN<7>")
	)
	(segment
		(start 43.148504 -293.105586)
		(end 43.621706 -293.105586)
		(width 0.20066)
		(layer "F.Cu")
		(net "M_B_CPU1_SA_DQS_DN<7>")
	)
	(segment
		(start 90.134694 -264.778236)
		(end 90.134694 -265.314176)
		(width 0.20066)
		(layer "F.Cu")
		(net "M_B_CPU1_SA_DQS_DN<7>")
	)
	(segment
		(start 44.736766 -292.951408)
		(end 44.746418 -292.941756)
		(width 0.101854)
		(layer "F.Cu")
		(net "M_B_CPU1_SA_DQS_DN<7>")
	)
	(segment
		(start 51.08956 -293.366698)
		(end 49.959514 -293.366698)
		(width 0.20066)
		(layer "F.Cu")
		(net "M_B_CPU1_SA_DQS_DN<7>")
	)
	(segment
		(start 47.46371 -292.680644)
		(end 47.868332 -292.680644)
		(width 0.20066)
		(layer "F.Cu")
		(net "M_B_CPU1_SA_DQS_DN<7>")
	)
	(segment
		(start 44.044108 -292.683184)
		(end 44.283884 -292.683184)
		(width 0.20066)
		(layer "F.Cu")
		(net "M_B_CPU1_SA_DQS_DN<7>")
	)
	(segment
		(start 51.089814 -293.366952)
		(end 51.08956 -293.366698)
		(width 0.20066)
		(layer "F.Cu")
		(net "M_B_CPU1_SA_DQS_DN<7>")
	)
	(segment
		(start 56.096916 -289.393884)
		(end 55.788306 -290.138866)
		(width 0.18288)
		(layer "In2.Cu")
		(net "M_B_CPU1_SA_DQS_DN<7>")
	)
	(segment
		(start 80.354932 -268.495526)
		(end 79.327248 -268.922754)
		(width 0.18288)
		(layer "In2.Cu")
		(net "M_B_CPU1_SA_DQS_DN<7>")
	)
	(segment
		(start 58.593228 -287.912302)
		(end 58.57748 -287.912302)
		(width 0.16002)
		(layer "In2.Cu")
		(net "M_B_CPU1_SA_DQS_DN<7>")
	)
	(segment
		(start 54.27726 -292.37813)
		(end 54.249066 -292.406324)
		(width 0.16002)
		(layer "In2.Cu")
		(net "M_B_CPU1_SA_DQS_DN<7>")
	)
	(segment
		(start 61.875162 -285.490412)
		(end 61.875162 -285.50616)
		(width 0.16002)
		(layer "In2.Cu")
		(net "M_B_CPU1_SA_DQS_DN<7>")
	)
	(segment
		(start 83.699858 -265.065764)
		(end 82.204306 -266.561316)
		(width 0.088646)
		(layer "In2.Cu")
		(net "M_B_CPU1_SA_DQS_DN<7>")
	)
	(segment
		(start 54.489604 -292.165786)
		(end 54.473856 -292.165786)
		(width 0.16002)
		(layer "In2.Cu")
		(net "M_B_CPU1_SA_DQS_DN<7>")
	)
	(segment
		(start 58.377328 -288.128202)
		(end 58.349134 -288.156396)
		(width 0.16002)
		(layer "In2.Cu")
		(net "M_B_CPU1_SA_DQS_DN<7>")
	)
	(segment
		(start 52.98821 -292.63467)
		(end 52.776628 -292.846252)
		(width 0.18288)
		(layer "In2.Cu")
		(net "M_B_CPU1_SA_DQS_DN<7>")
	)
	(segment
		(start 63.457582 -283.635958)
		(end 63.457582 -283.81198)
		(width 0.18288)
		(layer "In2.Cu")
		(net "M_B_CPU1_SA_DQS_DN<7>")
	)
	(segment
		(start 82.204306 -266.561316)
		(end 82.204306 -266.646152)
		(width 0.088646)
		(layer "In2.Cu")
		(net "M_B_CPU1_SA_DQS_DN<7>")
	)
	(segment
		(start 51.594004 -293.133018)
		(end 51.323748 -293.133018)
		(width 0.18288)
		(layer "In2.Cu")
		(net "M_B_CPU1_SA_DQS_DN<7>")
	)
	(segment
		(start 63.06947 -284.200092)
		(end 62.893448 -284.200092)
		(width 0.18288)
		(layer "In2.Cu")
		(net "M_B_CPU1_SA_DQS_DN<7>")
	)
	(segment
		(start 60.240672 -286.14878)
		(end 60.224416 -286.14878)
		(width 0.16002)
		(layer "In2.Cu")
		(net "M_B_CPU1_SA_DQS_DN<7>")
	)
	(segment
		(start 62.310518 -285.070804)
		(end 62.119256 -285.262066)
		(width 0.18288)
		(layer "In2.Cu")
		(net "M_B_CPU1_SA_DQS_DN<7>")
	)
	(segment
		(start 62.119256 -285.262066)
		(end 62.091062 -285.29026)
		(width 0.16002)
		(layer "In2.Cu")
		(net "M_B_CPU1_SA_DQS_DN<7>")
	)
	(segment
		(start 65.756028 -282.746196)
		(end 65.727834 -282.718002)
		(width 0.16002)
		(layer "In2.Cu")
		(net "M_B_CPU1_SA_DQS_DN<7>")
	)
	(segment
		(start 52.776628 -292.846252)
		(end 52.748434 -292.874446)
		(width 0.16002)
		(layer "In2.Cu")
		(net "M_B_CPU1_SA_DQS_DN<7>")
	)
	(segment
		(start 60.024772 -286.36468)
		(end 59.996578 -286.392874)
		(width 0.16002)
		(layer "In2.Cu")
		(net "M_B_CPU1_SA_DQS_DN<7>")
	)
	(segment
		(start 65.971928 -282.962096)
		(end 65.971928 -282.94584)
		(width 0.16002)
		(layer "In2.Cu")
		(net "M_B_CPU1_SA_DQS_DN<7>")
	)
	(segment
		(start 56.822594 -288.668206)
		(end 56.7944 -288.6964)
		(width 0.16002)
		(layer "In2.Cu")
		(net "M_B_CPU1_SA_DQS_DN<7>")
	)
	(segment
		(start 69.898006 -278.351996)
		(end 69.898006 -279.465786)
		(width 0.18288)
		(layer "In2.Cu")
		(net "M_B_CPU1_SA_DQS_DN<7>")
	)
	(segment
		(start 54.02072 -292.63467)
		(end 52.98821 -292.63467)
		(width 0.18288)
		(layer "In2.Cu")
		(net "M_B_CPU1_SA_DQS_DN<7>")
	)
	(segment
		(start 54.569868 -292.085522)
		(end 54.521354 -292.134036)
		(width 0.18288)
		(layer "In2.Cu")
		(net "M_B_CPU1_SA_DQS_DN<7>")
	)
	(segment
		(start 58.349134 -288.156396)
		(end 58.12536 -288.38017)
		(width 0.18288)
		(layer "In2.Cu")
		(net "M_B_CPU1_SA_DQS_DN<7>")
	)
	(segment
		(start 51.323748 -293.133018)
		(end 51.089814 -293.366952)
		(width 0.18288)
		(layer "In2.Cu")
		(net "M_B_CPU1_SA_DQS_DN<7>")
	)
	(segment
		(start 65.772284 -282.746196)
		(end 65.756028 -282.746196)
		(width 0.16002)
		(layer "In2.Cu")
		(net "M_B_CPU1_SA_DQS_DN<7>")
	)
	(segment
		(start 64.316356 -282.777184)
		(end 64.288162 -282.805378)
		(width 0.16002)
		(layer "In2.Cu")
		(net "M_B_CPU1_SA_DQS_DN<7>")
	)
	(segment
		(start 90.447368 -265.314176)
		(end 90.504772 -265.256772)
		(width 0.088646)
		(layer "In2.Cu")
		(net "M_B_CPU1_SA_DQS_DN<7>")
	)
	(segment
		(start 52.748434 -292.874446)
		(end 52.732178 -292.874446)
		(width 0.16002)
		(layer "In2.Cu")
		(net "M_B_CPU1_SA_DQS_DN<7>")
	)
	(segment
		(start 59.168538 -287.220914)
		(end 59.168538 -287.336992)
		(width 0.18288)
		(layer "In2.Cu")
		(net "M_B_CPU1_SA_DQS_DN<7>")
	)
	(segment
		(start 60.530994 -285.858458)
		(end 60.268866 -286.120586)
		(width 0.18288)
		(layer "In2.Cu")
		(net "M_B_CPU1_SA_DQS_DN<7>")
	)
	(segment
		(start 55.855616 -290.301426)
		(end 55.645558 -290.808664)
		(width 0.18288)
		(layer "In2.Cu")
		(net "M_B_CPU1_SA_DQS_DN<7>")
	)
	(segment
		(start 56.550306 -288.940494)
		(end 56.096916 -289.393884)
		(width 0.18288)
		(layer "In2.Cu")
		(net "M_B_CPU1_SA_DQS_DN<7>")
	)
	(segment
		(start 55.788306 -290.138866)
		(end 55.855616 -290.301426)
		(width 0.18288)
		(layer "In2.Cu")
		(net "M_B_CPU1_SA_DQS_DN<7>")
	)
	(segment
		(start 90.330782 -264.994898)
		(end 90.321892 -264.989818)
		(width 0.088646)
		(layer "In2.Cu")
		(net "M_B_CPU1_SA_DQS_DN<7>")
	)
	(segment
		(start 84.026502 -265.065764)
		(end 83.699858 -265.065764)
		(width 0.088646)
		(layer "In2.Cu")
		(net "M_B_CPU1_SA_DQS_DN<7>")
	)
	(segment
		(start 65.727834 -282.718002)
		(end 65.677542 -282.66771)
		(width 0.18288)
		(layer "In2.Cu")
		(net "M_B_CPU1_SA_DQS_DN<7>")
	)
	(segment
		(start 55.27294 -291.382704)
		(end 54.569868 -292.085522)
		(width 0.18288)
		(layer "In2.Cu")
		(net "M_B_CPU1_SA_DQS_DN<7>")
	)
	(segment
		(start 52.732178 -292.874446)
		(end 52.532534 -293.07409)
		(width 0.16002)
		(layer "In2.Cu")
		(net "M_B_CPU1_SA_DQS_DN<7>")
	)
	(segment
		(start 60.024772 -286.348424)
		(end 60.024772 -286.36468)
		(width 0.16002)
		(layer "In2.Cu")
		(net "M_B_CPU1_SA_DQS_DN<7>")
	)
	(segment
		(start 52.532534 -293.07409)
		(end 52.532534 -293.090346)
		(width 0.16002)
		(layer "In2.Cu")
		(net "M_B_CPU1_SA_DQS_DN<7>")
	)
	(segment
		(start 62.075314 -285.29026)
		(end 61.875162 -285.490412)
		(width 0.16002)
		(layer "In2.Cu")
		(net "M_B_CPU1_SA_DQS_DN<7>")
	)
	(segment
		(start 63.457582 -283.81198)
		(end 63.06947 -284.200092)
		(width 0.18288)
		(layer "In2.Cu")
		(net "M_B_CPU1_SA_DQS_DN<7>")
	)
	(segment
		(start 59.168538 -287.336992)
		(end 58.621422 -287.884108)
		(width 0.18288)
		(layer "In2.Cu")
		(net "M_B_CPU1_SA_DQS_DN<7>")
	)
	(segment
		(start 54.27726 -292.362382)
		(end 54.27726 -292.37813)
		(width 0.16002)
		(layer "In2.Cu")
		(net "M_B_CPU1_SA_DQS_DN<7>")
	)
	(segment
		(start 89.947496 -264.989818)
		(end 89.947242 -264.989564)
		(width 0.088646)
		(layer "In2.Cu")
		(net "M_B_CPU1_SA_DQS_DN<7>")
	)
	(segment
		(start 52.50434 -293.11854)
		(end 52.31511 -293.30777)
		(width 0.18288)
		(layer "In2.Cu")
		(net "M_B_CPU1_SA_DQS_DN<7>")
	)
	(segment
		(start 66.000122 -282.99029)
		(end 65.971928 -282.962096)
		(width 0.16002)
		(layer "In2.Cu")
		(net "M_B_CPU1_SA_DQS_DN<7>")
	)
	(segment
		(start 64.42583 -282.66771)
		(end 64.316356 -282.777184)
		(width 0.18288)
		(layer "In2.Cu")
		(net "M_B_CPU1_SA_DQS_DN<7>")
	)
	(segment
		(start 58.57748 -287.912302)
		(end 58.377328 -288.112454)
		(width 0.16002)
		(layer "In2.Cu")
		(net "M_B_CPU1_SA_DQS_DN<7>")
	)
	(segment
		(start 62.893448 -284.200092)
		(end 62.310518 -284.783022)
		(width 0.18288)
		(layer "In2.Cu")
		(net "M_B_CPU1_SA_DQS_DN<7>")
	)
	(segment
		(start 56.778144 -288.6964)
		(end 56.5785 -288.896044)
		(width 0.16002)
		(layer "In2.Cu")
		(net "M_B_CPU1_SA_DQS_DN<7>")
	)
	(segment
		(start 67.34175 -282.022042)
		(end 67.34175 -282.4734)
		(width 0.18288)
		(layer "In2.Cu")
		(net "M_B_CPU1_SA_DQS_DN<7>")
	)
	(segment
		(start 52.532534 -293.090346)
		(end 52.50434 -293.11854)
		(width 0.16002)
		(layer "In2.Cu")
		(net "M_B_CPU1_SA_DQS_DN<7>")
	)
	(segment
		(start 57.11063 -288.38017)
		(end 56.822594 -288.668206)
		(width 0.18288)
		(layer "In2.Cu")
		(net "M_B_CPU1_SA_DQS_DN<7>")
	)
	(segment
		(start 56.5785 -288.9123)
		(end 56.550306 -288.940494)
		(width 0.16002)
		(layer "In2.Cu")
		(net "M_B_CPU1_SA_DQS_DN<7>")
	)
	(segment
		(start 90.134694 -265.314176)
		(end 90.447368 -265.314176)
		(width 0.088646)
		(layer "In2.Cu")
		(net "M_B_CPU1_SA_DQS_DN<7>")
	)
	(segment
		(start 79.327248 -268.922754)
		(end 69.898006 -278.351996)
		(width 0.18288)
		(layer "In2.Cu")
		(net "M_B_CPU1_SA_DQS_DN<7>")
	)
	(segment
		(start 64.271906 -282.805378)
		(end 64.072262 -283.005022)
		(width 0.16002)
		(layer "In2.Cu")
		(net "M_B_CPU1_SA_DQS_DN<7>")
	)
	(segment
		(start 60.224416 -286.14878)
		(end 60.024772 -286.348424)
		(width 0.16002)
		(layer "In2.Cu")
		(net "M_B_CPU1_SA_DQS_DN<7>")
	)
	(segment
		(start 64.044068 -283.049472)
		(end 63.457582 -283.635958)
		(width 0.18288)
		(layer "In2.Cu")
		(net "M_B_CPU1_SA_DQS_DN<7>")
	)
	(segment
		(start 55.645558 -290.808664)
		(end 55.482744 -290.875974)
		(width 0.18288)
		(layer "In2.Cu")
		(net "M_B_CPU1_SA_DQS_DN<7>")
	)
	(segment
		(start 61.875162 -285.50616)
		(end 61.846968 -285.534354)
		(width 0.16002)
		(layer "In2.Cu")
		(net "M_B_CPU1_SA_DQS_DN<7>")
	)
	(segment
		(start 64.072262 -283.021278)
		(end 64.044068 -283.049472)
		(width 0.16002)
		(layer "In2.Cu")
		(net "M_B_CPU1_SA_DQS_DN<7>")
	)
	(segment
		(start 64.072262 -283.005022)
		(end 64.072262 -283.021278)
		(width 0.16002)
		(layer "In2.Cu")
		(net "M_B_CPU1_SA_DQS_DN<7>")
	)
	(segment
		(start 59.996578 -286.392874)
		(end 59.168538 -287.220914)
		(width 0.18288)
		(layer "In2.Cu")
		(net "M_B_CPU1_SA_DQS_DN<7>")
	)
	(segment
		(start 55.482744 -290.875974)
		(end 55.27294 -291.382704)
		(width 0.18288)
		(layer "In2.Cu")
		(net "M_B_CPU1_SA_DQS_DN<7>")
	)
	(segment
		(start 66.14541 -283.135578)
		(end 66.000122 -282.99029)
		(width 0.18288)
		(layer "In2.Cu")
		(net "M_B_CPU1_SA_DQS_DN<7>")
	)
	(segment
		(start 66.679572 -283.135578)
		(end 66.14541 -283.135578)
		(width 0.18288)
		(layer "In2.Cu")
		(net "M_B_CPU1_SA_DQS_DN<7>")
	)
	(segment
		(start 56.7944 -288.6964)
		(end 56.778144 -288.6964)
		(width 0.16002)
		(layer "In2.Cu")
		(net "M_B_CPU1_SA_DQS_DN<7>")
	)
	(segment
		(start 64.288162 -282.805378)
		(end 64.271906 -282.805378)
		(width 0.16002)
		(layer "In2.Cu")
		(net "M_B_CPU1_SA_DQS_DN<7>")
	)
	(segment
		(start 67.34175 -282.4734)
		(end 66.679572 -283.135578)
		(width 0.18288)
		(layer "In2.Cu")
		(net "M_B_CPU1_SA_DQS_DN<7>")
	)
	(segment
		(start 61.522864 -285.858458)
		(end 60.530994 -285.858458)
		(width 0.18288)
		(layer "In2.Cu")
		(net "M_B_CPU1_SA_DQS_DN<7>")
	)
	(segment
		(start 69.898006 -279.465786)
		(end 67.34175 -282.022042)
		(width 0.18288)
		(layer "In2.Cu")
		(net "M_B_CPU1_SA_DQS_DN<7>")
	)
	(segment
		(start 62.091062 -285.29026)
		(end 62.075314 -285.29026)
		(width 0.16002)
		(layer "In2.Cu")
		(net "M_B_CPU1_SA_DQS_DN<7>")
	)
	(segment
		(start 58.621422 -287.884108)
		(end 58.593228 -287.912302)
		(width 0.16002)
		(layer "In2.Cu")
		(net "M_B_CPU1_SA_DQS_DN<7>")
	)
	(segment
		(start 51.768756 -293.30777)
		(end 51.594004 -293.133018)
		(width 0.18288)
		(layer "In2.Cu")
		(net "M_B_CPU1_SA_DQS_DN<7>")
	)
	(segment
		(start 58.377328 -288.112454)
		(end 58.377328 -288.128202)
		(width 0.16002)
		(layer "In2.Cu")
		(net "M_B_CPU1_SA_DQS_DN<7>")
	)
	(segment
		(start 61.846968 -285.534354)
		(end 61.522864 -285.858458)
		(width 0.18288)
		(layer "In2.Cu")
		(net "M_B_CPU1_SA_DQS_DN<7>")
	)
	(segment
		(start 60.268866 -286.120586)
		(end 60.240672 -286.14878)
		(width 0.16002)
		(layer "In2.Cu")
		(net "M_B_CPU1_SA_DQS_DN<7>")
	)
	(segment
		(start 62.310518 -284.783022)
		(end 62.310518 -285.070804)
		(width 0.18288)
		(layer "In2.Cu")
		(net "M_B_CPU1_SA_DQS_DN<7>")
	)
	(segment
		(start 56.5785 -288.896044)
		(end 56.5785 -288.9123)
		(width 0.16002)
		(layer "In2.Cu")
		(net "M_B_CPU1_SA_DQS_DN<7>")
	)
	(segment
		(start 65.677542 -282.66771)
		(end 64.42583 -282.66771)
		(width 0.18288)
		(layer "In2.Cu")
		(net "M_B_CPU1_SA_DQS_DN<7>")
	)
	(segment
		(start 54.473856 -292.165786)
		(end 54.27726 -292.362382)
		(width 0.16002)
		(layer "In2.Cu")
		(net "M_B_CPU1_SA_DQS_DN<7>")
	)
	(segment
		(start 65.971928 -282.94584)
		(end 65.772284 -282.746196)
		(width 0.16002)
		(layer "In2.Cu")
		(net "M_B_CPU1_SA_DQS_DN<7>")
	)
	(segment
		(start 82.204306 -266.646152)
		(end 80.354932 -268.495526)
		(width 0.18288)
		(layer "In2.Cu")
		(net "M_B_CPU1_SA_DQS_DN<7>")
	)
	(segment
		(start 58.12536 -288.38017)
		(end 57.11063 -288.38017)
		(width 0.18288)
		(layer "In2.Cu")
		(net "M_B_CPU1_SA_DQS_DN<7>")
	)
	(segment
		(start 54.249066 -292.406324)
		(end 54.02072 -292.63467)
		(width 0.18288)
		(layer "In2.Cu")
		(net "M_B_CPU1_SA_DQS_DN<7>")
	)
	(segment
		(start 54.521354 -292.134036)
		(end 54.489604 -292.165786)
		(width 0.16002)
		(layer "In2.Cu")
		(net "M_B_CPU1_SA_DQS_DN<7>")
	)
	(segment
		(start 52.31511 -293.30777)
		(end 51.768756 -293.30777)
		(width 0.18288)
		(layer "In2.Cu")
		(net "M_B_CPU1_SA_DQS_DN<7>")
	)
	(arc
		(start 90.504772 -265.256772)
		(mid 90.446616 -265.106659)
		(end 90.330782 -264.994898)
		(width 0.088646)
		(layer "In2.Cu")
		(net "M_B_CPU1_SA_DQS_DN<7>")
	)
	(arc
		(start 86.188042 -264.989564)
		(mid 85.905594 -265.065247)
		(end 85.623146 -264.989564)
		(width 0.088646)
		(layer "In2.Cu")
		(net "M_B_CPU1_SA_DQS_DN<7>")
	)
	(arc
		(start 89.947242 -264.989564)
		(mid 89.664794 -265.065247)
		(end 89.382346 -264.989564)
		(width 0.088646)
		(layer "In2.Cu")
		(net "M_B_CPU1_SA_DQS_DN<7>")
	)
	(arc
		(start 86.562946 -264.989564)
		(mid 86.375494 -264.939328)
		(end 86.188042 -264.989564)
		(width 0.088646)
		(layer "In2.Cu")
		(net "M_B_CPU1_SA_DQS_DN<7>")
	)
	(arc
		(start 88.442546 -264.989564)
		(mid 88.255094 -264.939328)
		(end 88.067642 -264.989564)
		(width 0.088646)
		(layer "In2.Cu")
		(net "M_B_CPU1_SA_DQS_DN<7>")
	)
	(arc
		(start 89.007442 -264.989564)
		(mid 88.724994 -265.065247)
		(end 88.442546 -264.989564)
		(width 0.088646)
		(layer "In2.Cu")
		(net "M_B_CPU1_SA_DQS_DN<7>")
	)
	(arc
		(start 87.502746 -264.989564)
		(mid 87.315294 -264.939328)
		(end 87.127842 -264.989564)
		(width 0.088646)
		(layer "In2.Cu")
		(net "M_B_CPU1_SA_DQS_DN<7>")
	)
	(arc
		(start 85.623146 -264.989564)
		(mid 85.435694 -264.939328)
		(end 85.248242 -264.989564)
		(width 0.088646)
		(layer "In2.Cu")
		(net "M_B_CPU1_SA_DQS_DN<7>")
	)
	(arc
		(start 88.067642 -264.989564)
		(mid 87.785194 -265.065247)
		(end 87.502746 -264.989564)
		(width 0.088646)
		(layer "In2.Cu")
		(net "M_B_CPU1_SA_DQS_DN<7>")
	)
	(arc
		(start 87.127842 -264.989564)
		(mid 86.845394 -265.065247)
		(end 86.562946 -264.989564)
		(width 0.088646)
		(layer "In2.Cu")
		(net "M_B_CPU1_SA_DQS_DN<7>")
	)
	(arc
		(start 89.382346 -264.989564)
		(mid 89.194894 -264.939328)
		(end 89.007442 -264.989564)
		(width 0.088646)
		(layer "In2.Cu")
		(net "M_B_CPU1_SA_DQS_DN<7>")
	)
	(arc
		(start 84.308696 -264.989564)
		(mid 84.195922 -265.039452)
		(end 84.075016 -265.063732)
		(width 0.088646)
		(layer "In2.Cu")
		(net "M_B_CPU1_SA_DQS_DN<7>")
	)
	(arc
		(start 85.248242 -264.989564)
		(mid 84.965794 -265.065247)
		(end 84.683346 -264.989564)
		(width 0.088646)
		(layer "In2.Cu")
		(net "M_B_CPU1_SA_DQS_DN<7>")
	)
	(arc
		(start 84.075016 -265.063732)
		(mid 84.050781 -265.065274)
		(end 84.026502 -265.065764)
		(width 0.088646)
		(layer "In2.Cu")
		(net "M_B_CPU1_SA_DQS_DN<7>")
	)
	(arc
		(start 84.683346 -264.989564)
		(mid 84.496038 -264.939455)
		(end 84.308696 -264.989564)
		(width 0.088646)
		(layer "In2.Cu")
		(net "M_B_CPU1_SA_DQS_DN<7>")
	)
	(arc
		(start 90.321892 -264.989818)
		(mid 90.134694 -264.939675)
		(end 89.947496 -264.989818)
		(width 0.088646)
		(layer "In2.Cu")
		(net "M_B_CPU1_SA_DQS_DN<7>")
	)
	(segment
		(start 49.207928 -302.45558)
		(end 49.46904 -302.716692)
		(width 0.20066)
		(layer "F.Cu")
		(net "M_B_CPU1_SA_DQS_DN<6>")
	)
	(segment
		(start 47.060358 -302.29175)
		(end 47.202598 -302.29175)
		(width 0.20066)
		(layer "F.Cu")
		(net "M_B_CPU1_SA_DQS_DN<6>")
	)
	(segment
		(start 94.364048 -272.639028)
		(end 94.363794 -272.639282)
		(width 0.20066)
		(layer "F.Cu")
		(net "M_B_CPU1_SA_DQS_DN<6>")
	)
	(segment
		(start 44.283884 -302.033178)
		(end 44.552108 -302.301402)
		(width 0.20066)
		(layer "F.Cu")
		(net "M_B_CPU1_SA_DQS_DN<6>")
	)
	(segment
		(start 44.735242 -302.301402)
		(end 44.736766 -302.301402)
		(width 0.101854)
		(layer "F.Cu")
		(net "M_B_CPU1_SA_DQS_DN<6>")
	)
	(segment
		(start 43.148504 -302.45558)
		(end 43.621706 -302.45558)
		(width 0.20066)
		(layer "F.Cu")
		(net "M_B_CPU1_SA_DQS_DN<6>")
	)
	(segment
		(start 94.364048 -272.103342)
		(end 94.364048 -272.639028)
		(width 0.20066)
		(layer "F.Cu")
		(net "M_B_CPU1_SA_DQS_DN<6>")
	)
	(segment
		(start 49.46904 -302.716692)
		(end 49.959514 -302.716692)
		(width 0.20066)
		(layer "F.Cu")
		(net "M_B_CPU1_SA_DQS_DN<6>")
	)
	(segment
		(start 44.044108 -302.033178)
		(end 44.283884 -302.033178)
		(width 0.20066)
		(layer "F.Cu")
		(net "M_B_CPU1_SA_DQS_DN<6>")
	)
	(segment
		(start 44.736766 -302.301402)
		(end 44.746418 -302.29175)
		(width 0.101854)
		(layer "F.Cu")
		(net "M_B_CPU1_SA_DQS_DN<6>")
	)
	(segment
		(start 42.887392 -302.716692)
		(end 43.148504 -302.45558)
		(width 0.20066)
		(layer "F.Cu")
		(net "M_B_CPU1_SA_DQS_DN<6>")
	)
	(segment
		(start 44.746418 -302.29175)
		(end 44.982892 -302.29175)
		(width 0.101854)
		(layer "F.Cu")
		(net "M_B_CPU1_SA_DQS_DN<6>")
	)
	(segment
		(start 47.46371 -302.030638)
		(end 47.868332 -302.030638)
		(width 0.20066)
		(layer "F.Cu")
		(net "M_B_CPU1_SA_DQS_DN<6>")
	)
	(segment
		(start 51.08956 -302.716692)
		(end 49.959514 -302.716692)
		(width 0.20066)
		(layer "F.Cu")
		(net "M_B_CPU1_SA_DQS_DN<6>")
	)
	(segment
		(start 44.982892 -302.29175)
		(end 47.060358 -302.29175)
		(width 0.1016)
		(layer "F.Cu")
		(net "M_B_CPU1_SA_DQS_DN<6>")
	)
	(segment
		(start 42.415714 -302.716692)
		(end 42.887392 -302.716692)
		(width 0.20066)
		(layer "F.Cu")
		(net "M_B_CPU1_SA_DQS_DN<6>")
	)
	(segment
		(start 44.552108 -302.301402)
		(end 44.735242 -302.301402)
		(width 0.20066)
		(layer "F.Cu")
		(net "M_B_CPU1_SA_DQS_DN<6>")
	)
	(segment
		(start 43.621706 -302.45558)
		(end 44.044108 -302.033178)
		(width 0.20066)
		(layer "F.Cu")
		(net "M_B_CPU1_SA_DQS_DN<6>")
	)
	(segment
		(start 47.202598 -302.29175)
		(end 47.46371 -302.030638)
		(width 0.20066)
		(layer "F.Cu")
		(net "M_B_CPU1_SA_DQS_DN<6>")
	)
	(segment
		(start 51.089814 -302.716946)
		(end 51.08956 -302.716692)
		(width 0.20066)
		(layer "F.Cu")
		(net "M_B_CPU1_SA_DQS_DN<6>")
	)
	(segment
		(start 47.868332 -302.030638)
		(end 48.504348 -302.45558)
		(width 0.20066)
		(layer "F.Cu")
		(net "M_B_CPU1_SA_DQS_DN<6>")
	)
	(segment
		(start 48.504348 -302.45558)
		(end 49.207928 -302.45558)
		(width 0.20066)
		(layer "F.Cu")
		(net "M_B_CPU1_SA_DQS_DN<6>")
	)
	(segment
		(start 92.966032 -272.569432)
		(end 92.843858 -272.447258)
		(width 0.088646)
		(layer "In4.Cu")
		(net "M_B_CPU1_SA_DQS_DN<6>")
	)
	(segment
		(start 55.922926 -302.160178)
		(end 54.73573 -302.652176)
		(width 0.18288)
		(layer "In4.Cu")
		(net "M_B_CPU1_SA_DQS_DN<6>")
	)
	(segment
		(start 85.716872 -273.943318)
		(end 85.709506 -273.947636)
		(width 0.088646)
		(layer "In4.Cu")
		(net "M_B_CPU1_SA_DQS_DN<6>")
	)
	(segment
		(start 86.000844 -273.453098)
		(end 86.001098 -273.453098)
		(width 0.088646)
		(layer "In4.Cu")
		(net "M_B_CPU1_SA_DQS_DN<6>")
	)
	(segment
		(start 72.779636 -292.522402)
		(end 68.129404 -297.17238)
		(width 0.18288)
		(layer "In4.Cu")
		(net "M_B_CPU1_SA_DQS_DN<6>")
	)
	(segment
		(start 54.73573 -302.652176)
		(end 51.922172 -302.652176)
		(width 0.18288)
		(layer "In4.Cu")
		(net "M_B_CPU1_SA_DQS_DN<6>")
	)
	(segment
		(start 60.98286 -298.616624)
		(end 60.603892 -298.995592)
		(width 0.18288)
		(layer "In4.Cu")
		(net "M_B_CPU1_SA_DQS_DN<6>")
	)
	(segment
		(start 86.194646 -273.125184)
		(end 86.18855 -273.12874)
		(width 0.088646)
		(layer "In4.Cu")
		(net "M_B_CPU1_SA_DQS_DN<6>")
	)
	(segment
		(start 51.364642 -302.442118)
		(end 51.089814 -302.716946)
		(width 0.18288)
		(layer "In4.Cu")
		(net "M_B_CPU1_SA_DQS_DN<6>")
	)
	(segment
		(start 62.493144 -298.622212)
		(end 62.223396 -298.89196)
		(width 0.18288)
		(layer "In4.Cu")
		(net "M_B_CPU1_SA_DQS_DN<6>")
	)
	(segment
		(start 51.712114 -302.442118)
		(end 51.364642 -302.442118)
		(width 0.18288)
		(layer "In4.Cu")
		(net "M_B_CPU1_SA_DQS_DN<6>")
	)
	(segment
		(start 58.751724 -300.504098)
		(end 58.20537 -300.504098)
		(width 0.18288)
		(layer "In4.Cu")
		(net "M_B_CPU1_SA_DQS_DN<6>")
	)
	(segment
		(start 85.718396 -273.942556)
		(end 85.716872 -273.943318)
		(width 0.088646)
		(layer "In4.Cu")
		(net "M_B_CPU1_SA_DQS_DN<6>")
	)
	(segment
		(start 89.862406 -272.32102)
		(end 89.851992 -272.314924)
		(width 0.088646)
		(layer "In4.Cu")
		(net "M_B_CPU1_SA_DQS_DN<6>")
	)
	(segment
		(start 61.85408 -298.89196)
		(end 61.578744 -298.616624)
		(width 0.18288)
		(layer "In4.Cu")
		(net "M_B_CPU1_SA_DQS_DN<6>")
	)
	(segment
		(start 89.477596 -272.314924)
		(end 89.467182 -272.32102)
		(width 0.088646)
		(layer "In4.Cu")
		(net "M_B_CPU1_SA_DQS_DN<6>")
	)
	(segment
		(start 85.248242 -274.756372)
		(end 85.246718 -274.757134)
		(width 0.088646)
		(layer "In4.Cu")
		(net "M_B_CPU1_SA_DQS_DN<6>")
	)
	(segment
		(start 90.80246 -272.32102)
		(end 90.792046 -272.314924)
		(width 0.088646)
		(layer "In4.Cu")
		(net "M_B_CPU1_SA_DQS_DN<6>")
	)
	(segment
		(start 56.54929 -302.160178)
		(end 55.922926 -302.160178)
		(width 0.18288)
		(layer "In4.Cu")
		(net "M_B_CPU1_SA_DQS_DN<6>")
	)
	(segment
		(start 85.254338 -274.752816)
		(end 85.251036 -274.754848)
		(width 0.088646)
		(layer "In4.Cu")
		(net "M_B_CPU1_SA_DQS_DN<6>")
	)
	(segment
		(start 85.724492 -273.939)
		(end 85.72119 -273.941032)
		(width 0.088646)
		(layer "In4.Cu")
		(net "M_B_CPU1_SA_DQS_DN<6>")
	)
	(segment
		(start 82.661506 -277.343108)
		(end 82.662268 -277.343616)
		(width 0.18288)
		(layer "In4.Cu")
		(net "M_B_CPU1_SA_DQS_DN<6>")
	)
	(segment
		(start 92.296996 -272.314924)
		(end 92.282264 -272.32356)
		(width 0.088646)
		(layer "In4.Cu")
		(net "M_B_CPU1_SA_DQS_DN<6>")
	)
	(segment
		(start 86.65845 -272.314924)
		(end 86.64956 -272.320004)
		(width 0.088646)
		(layer "In4.Cu")
		(net "M_B_CPU1_SA_DQS_DN<6>")
	)
	(segment
		(start 83.88477 -276.319742)
		(end 83.824826 -276.379686)
		(width 0.088646)
		(layer "In4.Cu")
		(net "M_B_CPU1_SA_DQS_DN<6>")
	)
	(segment
		(start 62.223396 -298.89196)
		(end 61.85408 -298.89196)
		(width 0.18288)
		(layer "In4.Cu")
		(net "M_B_CPU1_SA_DQS_DN<6>")
	)
	(segment
		(start 85.72119 -273.941032)
		(end 85.718396 -273.942556)
		(width 0.088646)
		(layer "In4.Cu")
		(net "M_B_CPU1_SA_DQS_DN<6>")
	)
	(segment
		(start 68.129404 -297.17238)
		(end 65.671954 -297.17238)
		(width 0.18288)
		(layer "In4.Cu")
		(net "M_B_CPU1_SA_DQS_DN<6>")
	)
	(segment
		(start 58.20537 -300.504098)
		(end 56.54929 -302.160178)
		(width 0.18288)
		(layer "In4.Cu")
		(net "M_B_CPU1_SA_DQS_DN<6>")
	)
	(segment
		(start 84.10448 -276.319742)
		(end 83.88477 -276.319742)
		(width 0.088646)
		(layer "In4.Cu")
		(net "M_B_CPU1_SA_DQS_DN<6>")
	)
	(segment
		(start 85.246718 -274.757134)
		(end 85.245956 -274.757896)
		(width 0.088646)
		(layer "In4.Cu")
		(net "M_B_CPU1_SA_DQS_DN<6>")
	)
	(segment
		(start 87.04326 -272.32102)
		(end 87.032846 -272.314924)
		(width 0.088646)
		(layer "In4.Cu")
		(net "M_B_CPU1_SA_DQS_DN<6>")
	)
	(segment
		(start 86.18855 -273.12874)
		(end 86.173564 -273.137376)
		(width 0.088646)
		(layer "In4.Cu")
		(net "M_B_CPU1_SA_DQS_DN<6>")
	)
	(segment
		(start 85.060536 -275.101812)
		(end 85.031326 -275.392896)
		(width 0.088646)
		(layer "In4.Cu")
		(net "M_B_CPU1_SA_DQS_DN<6>")
	)
	(segment
		(start 60.017152 -299.23867)
		(end 58.751724 -300.504098)
		(width 0.18288)
		(layer "In4.Cu")
		(net "M_B_CPU1_SA_DQS_DN<6>")
	)
	(segment
		(start 85.031326 -275.392896)
		(end 84.10448 -276.319742)
		(width 0.088646)
		(layer "In4.Cu")
		(net "M_B_CPU1_SA_DQS_DN<6>")
	)
	(segment
		(start 60.603892 -298.995592)
		(end 60.017152 -299.23867)
		(width 0.18288)
		(layer "In4.Cu")
		(net "M_B_CPU1_SA_DQS_DN<6>")
	)
	(segment
		(start 64.222122 -298.622212)
		(end 62.493144 -298.622212)
		(width 0.18288)
		(layer "In4.Cu")
		(net "M_B_CPU1_SA_DQS_DN<6>")
	)
	(segment
		(start 83.824826 -276.379686)
		(end 83.801458 -276.379686)
		(width 0.088646)
		(layer "In4.Cu")
		(net "M_B_CPU1_SA_DQS_DN<6>")
	)
	(segment
		(start 87.982806 -272.32102)
		(end 87.972392 -272.314924)
		(width 0.088646)
		(layer "In4.Cu")
		(net "M_B_CPU1_SA_DQS_DN<6>")
	)
	(segment
		(start 85.060536 -275.080984)
		(end 85.060536 -275.101812)
		(width 0.088646)
		(layer "In4.Cu")
		(net "M_B_CPU1_SA_DQS_DN<6>")
	)
	(segment
		(start 85.06079 -275.08073)
		(end 85.060536 -275.080984)
		(width 0.088646)
		(layer "In4.Cu")
		(net "M_B_CPU1_SA_DQS_DN<6>")
	)
	(segment
		(start 51.922172 -302.652176)
		(end 51.712114 -302.442118)
		(width 0.18288)
		(layer "In4.Cu")
		(net "M_B_CPU1_SA_DQS_DN<6>")
	)
	(segment
		(start 65.671954 -297.17238)
		(end 64.222122 -298.622212)
		(width 0.18288)
		(layer "In4.Cu")
		(net "M_B_CPU1_SA_DQS_DN<6>")
	)
	(segment
		(start 82.662268 -277.343616)
		(end 76.514452 -283.506418)
		(width 0.18288)
		(layer "In4.Cu")
		(net "M_B_CPU1_SA_DQS_DN<6>")
	)
	(segment
		(start 85.245956 -274.757896)
		(end 85.239352 -274.761452)
		(width 0.088646)
		(layer "In4.Cu")
		(net "M_B_CPU1_SA_DQS_DN<6>")
	)
	(segment
		(start 83.62442 -276.379686)
		(end 82.661506 -277.343108)
		(width 0.18288)
		(layer "In4.Cu")
		(net "M_B_CPU1_SA_DQS_DN<6>")
	)
	(segment
		(start 61.578744 -298.616624)
		(end 60.98286 -298.616624)
		(width 0.18288)
		(layer "In4.Cu")
		(net "M_B_CPU1_SA_DQS_DN<6>")
	)
	(segment
		(start 76.514452 -283.506418)
		(end 72.779636 -292.522402)
		(width 0.18288)
		(layer "In4.Cu")
		(net "M_B_CPU1_SA_DQS_DN<6>")
	)
	(segment
		(start 83.801458 -276.379686)
		(end 83.62442 -276.379686)
		(width 0.18288)
		(layer "In4.Cu")
		(net "M_B_CPU1_SA_DQS_DN<6>")
	)
	(segment
		(start 94.363794 -272.639282)
		(end 93.686376 -272.927064)
		(width 0.088646)
		(layer "In4.Cu")
		(net "M_B_CPU1_SA_DQS_DN<6>")
	)
	(segment
		(start 85.251036 -274.754848)
		(end 85.248242 -274.756372)
		(width 0.088646)
		(layer "In4.Cu")
		(net "M_B_CPU1_SA_DQS_DN<6>")
	)
	(arc
		(start 86.64956 -272.320004)
		(mid 86.518646 -272.456364)
		(end 86.470998 -272.639282)
		(width 0.088646)
		(layer "In4.Cu")
		(net "M_B_CPU1_SA_DQS_DN<6>")
	)
	(arc
		(start 87.032846 -272.314924)
		(mid 86.845648 -272.264781)
		(end 86.65845 -272.314924)
		(width 0.088646)
		(layer "In4.Cu")
		(net "M_B_CPU1_SA_DQS_DN<6>")
	)
	(arc
		(start 88.912446 -272.314924)
		(mid 88.725248 -272.264781)
		(end 88.53805 -272.314924)
		(width 0.088646)
		(layer "In4.Cu")
		(net "M_B_CPU1_SA_DQS_DN<6>")
	)
	(arc
		(start 91.731592 -272.314924)
		(mid 91.544394 -272.264781)
		(end 91.357196 -272.314924)
		(width 0.088646)
		(layer "In4.Cu")
		(net "M_B_CPU1_SA_DQS_DN<6>")
	)
	(arc
		(start 86.001098 -273.453098)
		(mid 85.927107 -273.732664)
		(end 85.724492 -273.939)
		(width 0.088646)
		(layer "In4.Cu")
		(net "M_B_CPU1_SA_DQS_DN<6>")
	)
	(arc
		(start 85.239352 -274.761452)
		(mid 85.108438 -274.897812)
		(end 85.06079 -275.08073)
		(width 0.088646)
		(layer "In4.Cu")
		(net "M_B_CPU1_SA_DQS_DN<6>")
	)
	(arc
		(start 91.357196 -272.314924)
		(mid 91.080637 -272.390633)
		(end 90.80246 -272.32102)
		(width 0.088646)
		(layer "In4.Cu")
		(net "M_B_CPU1_SA_DQS_DN<6>")
	)
	(arc
		(start 90.41765 -272.314924)
		(mid 90.140837 -272.39076)
		(end 89.862406 -272.32102)
		(width 0.088646)
		(layer "In4.Cu")
		(net "M_B_CPU1_SA_DQS_DN<6>")
	)
	(arc
		(start 89.851992 -272.314924)
		(mid 89.664794 -272.264781)
		(end 89.477596 -272.314924)
		(width 0.088646)
		(layer "In4.Cu")
		(net "M_B_CPU1_SA_DQS_DN<6>")
	)
	(arc
		(start 86.470998 -272.639282)
		(mid 86.397082 -272.918784)
		(end 86.194646 -273.125184)
		(width 0.088646)
		(layer "In4.Cu")
		(net "M_B_CPU1_SA_DQS_DN<6>")
	)
	(arc
		(start 85.709506 -273.947636)
		(mid 85.578592 -274.083996)
		(end 85.530944 -274.266914)
		(width 0.088646)
		(layer "In4.Cu")
		(net "M_B_CPU1_SA_DQS_DN<6>")
	)
	(arc
		(start 92.671392 -272.314924)
		(mid 92.484194 -272.264781)
		(end 92.296996 -272.314924)
		(width 0.088646)
		(layer "In4.Cu")
		(net "M_B_CPU1_SA_DQS_DN<6>")
	)
	(arc
		(start 86.173564 -273.137376)
		(mid 86.046841 -273.273157)
		(end 86.000844 -273.453098)
		(width 0.088646)
		(layer "In4.Cu")
		(net "M_B_CPU1_SA_DQS_DN<6>")
	)
	(arc
		(start 93.686376 -272.927064)
		(mid 93.645969 -272.945677)
		(end 93.60662 -272.966434)
		(width 0.088646)
		(layer "In4.Cu")
		(net "M_B_CPU1_SA_DQS_DN<6>")
	)
	(arc
		(start 92.843858 -272.447258)
		(mid 92.761971 -272.375426)
		(end 92.671392 -272.314924)
		(width 0.088646)
		(layer "In4.Cu")
		(net "M_B_CPU1_SA_DQS_DN<6>")
	)
	(arc
		(start 85.530944 -274.266914)
		(mid 85.456953 -274.54648)
		(end 85.254338 -274.752816)
		(width 0.088646)
		(layer "In4.Cu")
		(net "M_B_CPU1_SA_DQS_DN<6>")
	)
	(arc
		(start 87.597996 -272.314924)
		(mid 87.321437 -272.390633)
		(end 87.04326 -272.32102)
		(width 0.088646)
		(layer "In4.Cu")
		(net "M_B_CPU1_SA_DQS_DN<6>")
	)
	(arc
		(start 90.792046 -272.314924)
		(mid 90.604848 -272.264781)
		(end 90.41765 -272.314924)
		(width 0.088646)
		(layer "In4.Cu")
		(net "M_B_CPU1_SA_DQS_DN<6>")
	)
	(arc
		(start 89.467182 -272.32102)
		(mid 89.189004 -272.390712)
		(end 88.912446 -272.314924)
		(width 0.088646)
		(layer "In4.Cu")
		(net "M_B_CPU1_SA_DQS_DN<6>")
	)
	(arc
		(start 93.60662 -272.966434)
		(mid 93.278194 -272.984437)
		(end 93.062298 -272.73631)
		(width 0.088646)
		(layer "In4.Cu")
		(net "M_B_CPU1_SA_DQS_DN<6>")
	)
	(arc
		(start 88.53805 -272.314924)
		(mid 88.261237 -272.39076)
		(end 87.982806 -272.32102)
		(width 0.088646)
		(layer "In4.Cu")
		(net "M_B_CPU1_SA_DQS_DN<6>")
	)
	(arc
		(start 93.062298 -272.73631)
		(mid 93.025127 -272.646552)
		(end 92.966032 -272.569432)
		(width 0.088646)
		(layer "In4.Cu")
		(net "M_B_CPU1_SA_DQS_DN<6>")
	)
	(arc
		(start 87.972392 -272.314924)
		(mid 87.785194 -272.264781)
		(end 87.597996 -272.314924)
		(width 0.088646)
		(layer "In4.Cu")
		(net "M_B_CPU1_SA_DQS_DN<6>")
	)
	(arc
		(start 92.282264 -272.32356)
		(mid 92.005823 -272.390726)
		(end 91.731592 -272.314924)
		(width 0.088646)
		(layer "In4.Cu")
		(net "M_B_CPU1_SA_DQS_DN<6>")
	)
	(segment
		(start 44.736766 -311.651396)
		(end 44.735242 -311.651396)
		(width 0.101854)
		(layer "F.Cu")
		(net "M_B_CPU1_SA_DQS_DN<5>")
	)
	(segment
		(start 49.959514 -312.066686)
		(end 49.46904 -312.066686)
		(width 0.20066)
		(layer "F.Cu")
		(net "M_B_CPU1_SA_DQS_DN<5>")
	)
	(segment
		(start 44.746418 -311.641744)
		(end 44.736766 -311.651396)
		(width 0.101854)
		(layer "F.Cu")
		(net "M_B_CPU1_SA_DQS_DN<5>")
	)
	(segment
		(start 43.148504 -311.805574)
		(end 42.887392 -312.066686)
		(width 0.20066)
		(layer "F.Cu")
		(net "M_B_CPU1_SA_DQS_DN<5>")
	)
	(segment
		(start 44.283884 -311.383172)
		(end 44.044108 -311.383172)
		(width 0.20066)
		(layer "F.Cu")
		(net "M_B_CPU1_SA_DQS_DN<5>")
	)
	(segment
		(start 43.621706 -311.805574)
		(end 43.148504 -311.805574)
		(width 0.20066)
		(layer "F.Cu")
		(net "M_B_CPU1_SA_DQS_DN<5>")
	)
	(segment
		(start 47.202598 -311.641744)
		(end 47.060358 -311.641744)
		(width 0.20066)
		(layer "F.Cu")
		(net "M_B_CPU1_SA_DQS_DN<5>")
	)
	(segment
		(start 90.134694 -274.54479)
		(end 90.134694 -275.08073)
		(width 0.20066)
		(layer "F.Cu")
		(net "M_B_CPU1_SA_DQS_DN<5>")
	)
	(segment
		(start 47.060358 -311.641744)
		(end 44.982892 -311.641744)
		(width 0.1016)
		(layer "F.Cu")
		(net "M_B_CPU1_SA_DQS_DN<5>")
	)
	(segment
		(start 47.868332 -311.380632)
		(end 47.46371 -311.380632)
		(width 0.20066)
		(layer "F.Cu")
		(net "M_B_CPU1_SA_DQS_DN<5>")
	)
	(segment
		(start 44.044108 -311.383172)
		(end 43.621706 -311.805574)
		(width 0.20066)
		(layer "F.Cu")
		(net "M_B_CPU1_SA_DQS_DN<5>")
	)
	(segment
		(start 42.887392 -312.066686)
		(end 42.415714 -312.066686)
		(width 0.20066)
		(layer "F.Cu")
		(net "M_B_CPU1_SA_DQS_DN<5>")
	)
	(segment
		(start 44.735242 -311.651396)
		(end 44.552108 -311.651396)
		(width 0.20066)
		(layer "F.Cu")
		(net "M_B_CPU1_SA_DQS_DN<5>")
	)
	(segment
		(start 49.46904 -312.066686)
		(end 49.207928 -311.805574)
		(width 0.20066)
		(layer "F.Cu")
		(net "M_B_CPU1_SA_DQS_DN<5>")
	)
	(segment
		(start 48.504348 -311.805574)
		(end 47.868332 -311.380632)
		(width 0.20066)
		(layer "F.Cu")
		(net "M_B_CPU1_SA_DQS_DN<5>")
	)
	(segment
		(start 49.207928 -311.805574)
		(end 48.504348 -311.805574)
		(width 0.20066)
		(layer "F.Cu")
		(net "M_B_CPU1_SA_DQS_DN<5>")
	)
	(segment
		(start 44.552108 -311.651396)
		(end 44.283884 -311.383172)
		(width 0.20066)
		(layer "F.Cu")
		(net "M_B_CPU1_SA_DQS_DN<5>")
	)
	(segment
		(start 47.46371 -311.380632)
		(end 47.202598 -311.641744)
		(width 0.20066)
		(layer "F.Cu")
		(net "M_B_CPU1_SA_DQS_DN<5>")
	)
	(segment
		(start 44.982892 -311.641744)
		(end 44.746418 -311.641744)
		(width 0.101854)
		(layer "F.Cu")
		(net "M_B_CPU1_SA_DQS_DN<5>")
	)
	(segment
		(start 51.089814 -312.066686)
		(end 49.959514 -312.066686)
		(width 0.20066)
		(layer "F.Cu")
		(net "M_B_CPU1_SA_DQS_DN<5>")
	)
	(segment
		(start 66.685922 -311.29732)
		(end 66.25209 -311.29732)
		(width 0.18288)
		(layer "In2.Cu")
		(net "M_B_CPU1_SA_DQS_DN<5>")
	)
	(segment
		(start 54.164738 -311.703974)
		(end 54.136544 -311.67578)
		(width 0.16002)
		(layer "In2.Cu")
		(net "M_B_CPU1_SA_DQS_DN<5>")
	)
	(segment
		(start 78.196186 -291.056568)
		(end 78.033372 -291.124132)
		(width 0.18288)
		(layer "In2.Cu")
		(net "M_B_CPU1_SA_DQS_DN<5>")
	)
	(segment
		(start 79.188056 -288.336736)
		(end 78.338934 -290.387024)
		(width 0.18288)
		(layer "In2.Cu")
		(net "M_B_CPU1_SA_DQS_DN<5>")
	)
	(segment
		(start 56.748172 -312.874406)
		(end 56.550814 -312.677048)
		(width 0.18288)
		(layer "In2.Cu")
		(net "M_B_CPU1_SA_DQS_DN<5>")
	)
	(segment
		(start 65.780412 -310.825642)
		(end 65.673732 -310.718962)
		(width 0.18288)
		(layer "In2.Cu")
		(net "M_B_CPU1_SA_DQS_DN<5>")
	)
	(segment
		(start 90.447368 -275.08073)
		(end 90.504772 -275.023326)
		(width 0.088646)
		(layer "In2.Cu")
		(net "M_B_CPU1_SA_DQS_DN<5>")
	)
	(segment
		(start 61.573664 -311.568846)
		(end 60.320428 -311.568846)
		(width 0.18288)
		(layer "In2.Cu")
		(net "M_B_CPU1_SA_DQS_DN<5>")
	)
	(segment
		(start 58.68416 -312.432954)
		(end 58.484008 -312.633106)
		(width 0.16002)
		(layer "In2.Cu")
		(net "M_B_CPU1_SA_DQS_DN<5>")
	)
	(segment
		(start 79.188564 -288.336228)
		(end 79.188056 -288.336736)
		(width 0.18288)
		(layer "In2.Cu")
		(net "M_B_CPU1_SA_DQS_DN<5>")
	)
	(segment
		(start 58.484008 -312.633106)
		(end 58.484008 -312.648854)
		(width 0.16002)
		(layer "In2.Cu")
		(net "M_B_CPU1_SA_DQS_DN<5>")
	)
	(segment
		(start 86.656418 -277.846282)
		(end 86.657942 -277.847044)
		(width 0.088646)
		(layer "In2.Cu")
		(net "M_B_CPU1_SA_DQS_DN<5>")
	)
	(segment
		(start 72.687688 -305.505358)
		(end 67.043554 -311.148984)
		(width 0.18288)
		(layer "In2.Cu")
		(net "M_B_CPU1_SA_DQS_DN<5>")
	)
	(segment
		(start 58.699908 -312.432954)
		(end 58.68416 -312.432954)
		(width 0.16002)
		(layer "In2.Cu")
		(net "M_B_CPU1_SA_DQS_DN<5>")
	)
	(segment
		(start 56.089296 -312.21553)
		(end 54.676294 -312.21553)
		(width 0.18288)
		(layer "In2.Cu")
		(net "M_B_CPU1_SA_DQS_DN<5>")
	)
	(segment
		(start 58.484008 -312.648854)
		(end 58.455814 -312.677048)
		(width 0.16002)
		(layer "In2.Cu")
		(net "M_B_CPU1_SA_DQS_DN<5>")
	)
	(segment
		(start 77.68082 -292.30066)
		(end 77.518006 -292.36797)
		(width 0.18288)
		(layer "In2.Cu")
		(net "M_B_CPU1_SA_DQS_DN<5>")
	)
	(segment
		(start 86.659466 -276.220174)
		(end 86.660736 -276.220936)
		(width 0.088646)
		(layer "In2.Cu")
		(net "M_B_CPU1_SA_DQS_DN<5>")
	)
	(segment
		(start 52.903374 -311.442354)
		(end 52.708048 -311.63768)
		(width 0.18288)
		(layer "In2.Cu")
		(net "M_B_CPU1_SA_DQS_DN<5>")
	)
	(segment
		(start 56.550814 -312.677048)
		(end 56.52262 -312.648854)
		(width 0.16002)
		(layer "In2.Cu")
		(net "M_B_CPU1_SA_DQS_DN<5>")
	)
	(segment
		(start 58.935112 -312.19775)
		(end 58.728102 -312.40476)
		(width 0.18288)
		(layer "In2.Cu")
		(net "M_B_CPU1_SA_DQS_DN<5>")
	)
	(segment
		(start 52.43576 -311.909968)
		(end 52.309268 -312.03646)
		(width 0.18288)
		(layer "In2.Cu")
		(net "M_B_CPU1_SA_DQS_DN<5>")
	)
	(segment
		(start 58.258456 -312.874406)
		(end 56.748172 -312.874406)
		(width 0.18288)
		(layer "In2.Cu")
		(net "M_B_CPU1_SA_DQS_DN<5>")
	)
	(segment
		(start 86.940136 -275.07565)
		(end 86.940136 -275.09978)
		(width 0.088646)
		(layer "In2.Cu")
		(net "M_B_CPU1_SA_DQS_DN<5>")
	)
	(segment
		(start 56.278526 -312.40476)
		(end 56.089296 -312.21553)
		(width 0.18288)
		(layer "In2.Cu")
		(net "M_B_CPU1_SA_DQS_DN<5>")
	)
	(segment
		(start 59.691524 -312.19775)
		(end 58.935112 -312.19775)
		(width 0.18288)
		(layer "In2.Cu")
		(net "M_B_CPU1_SA_DQS_DN<5>")
	)
	(segment
		(start 56.322468 -312.432954)
		(end 56.30672 -312.432954)
		(width 0.16002)
		(layer "In2.Cu")
		(net "M_B_CPU1_SA_DQS_DN<5>")
	)
	(segment
		(start 86.657942 -277.198328)
		(end 86.649052 -277.203408)
		(width 0.088646)
		(layer "In2.Cu")
		(net "M_B_CPU1_SA_DQS_DN<5>")
	)
	(segment
		(start 52.663598 -311.665874)
		(end 52.463954 -311.865518)
		(width 0.16002)
		(layer "In2.Cu")
		(net "M_B_CPU1_SA_DQS_DN<5>")
	)
	(segment
		(start 90.134694 -275.08073)
		(end 90.447368 -275.08073)
		(width 0.088646)
		(layer "In2.Cu")
		(net "M_B_CPU1_SA_DQS_DN<5>")
	)
	(segment
		(start 51.769772 -312.03646)
		(end 51.523646 -311.790334)
		(width 0.18288)
		(layer "In2.Cu")
		(net "M_B_CPU1_SA_DQS_DN<5>")
	)
	(segment
		(start 74.163174 -301.942754)
		(end 72.687688 -305.505358)
		(width 0.18288)
		(layer "In2.Cu")
		(net "M_B_CPU1_SA_DQS_DN<5>")
	)
	(segment
		(start 66.024506 -311.069736)
		(end 66.024506 -311.05348)
		(width 0.16002)
		(layer "In2.Cu")
		(net "M_B_CPU1_SA_DQS_DN<5>")
	)
	(segment
		(start 62.982348 -312.15711)
		(end 62.161928 -312.15711)
		(width 0.18288)
		(layer "In2.Cu")
		(net "M_B_CPU1_SA_DQS_DN<5>")
	)
	(segment
		(start 59.94146 -311.947814)
		(end 59.691524 -312.19775)
		(width 0.18288)
		(layer "In2.Cu")
		(net "M_B_CPU1_SA_DQS_DN<5>")
	)
	(segment
		(start 66.024506 -311.05348)
		(end 65.824862 -310.853836)
		(width 0.16002)
		(layer "In2.Cu")
		(net "M_B_CPU1_SA_DQS_DN<5>")
	)
	(segment
		(start 84.868512 -279.442164)
		(end 84.868512 -279.527)
		(width 0.088646)
		(layer "In2.Cu")
		(net "M_B_CPU1_SA_DQS_DN<5>")
	)
	(segment
		(start 88.067896 -274.756372)
		(end 88.057482 -274.762468)
		(width 0.088646)
		(layer "In2.Cu")
		(net "M_B_CPU1_SA_DQS_DN<5>")
	)
	(segment
		(start 77.890878 -291.793422)
		(end 77.68082 -292.30066)
		(width 0.18288)
		(layer "In2.Cu")
		(net "M_B_CPU1_SA_DQS_DN<5>")
	)
	(segment
		(start 74.727816 -299.10405)
		(end 74.163174 -301.942754)
		(width 0.18288)
		(layer "In2.Cu")
		(net "M_B_CPU1_SA_DQS_DN<5>")
	)
	(segment
		(start 54.380638 -311.919874)
		(end 54.380638 -311.903618)
		(width 0.16002)
		(layer "In2.Cu")
		(net "M_B_CPU1_SA_DQS_DN<5>")
	)
	(segment
		(start 61.680344 -311.675526)
		(end 61.573664 -311.568846)
		(width 0.18288)
		(layer "In2.Cu")
		(net "M_B_CPU1_SA_DQS_DN<5>")
	)
	(segment
		(start 59.969654 -311.903364)
		(end 59.969654 -311.91962)
		(width 0.16002)
		(layer "In2.Cu")
		(net "M_B_CPU1_SA_DQS_DN<5>")
	)
	(segment
		(start 51.523646 -311.790334)
		(end 51.366166 -311.790334)
		(width 0.18288)
		(layer "In2.Cu")
		(net "M_B_CPU1_SA_DQS_DN<5>")
	)
	(segment
		(start 65.824862 -310.853836)
		(end 65.808606 -310.853836)
		(width 0.16002)
		(layer "In2.Cu")
		(net "M_B_CPU1_SA_DQS_DN<5>")
	)
	(segment
		(start 61.924438 -311.903364)
		(end 61.724794 -311.70372)
		(width 0.16002)
		(layer "In2.Cu")
		(net "M_B_CPU1_SA_DQS_DN<5>")
	)
	(segment
		(start 58.728102 -312.40476)
		(end 58.699908 -312.432954)
		(width 0.16002)
		(layer "In2.Cu")
		(net "M_B_CPU1_SA_DQS_DN<5>")
	)
	(segment
		(start 82.859118 -283.413454)
		(end 82.676238 -283.854906)
		(width 0.18288)
		(layer "In2.Cu")
		(net "M_B_CPU1_SA_DQS_DN<5>")
	)
	(segment
		(start 61.724794 -311.70372)
		(end 61.708538 -311.70372)
		(width 0.16002)
		(layer "In2.Cu")
		(net "M_B_CPU1_SA_DQS_DN<5>")
	)
	(segment
		(start 52.463954 -311.881774)
		(end 52.43576 -311.909968)
		(width 0.16002)
		(layer "In2.Cu")
		(net "M_B_CPU1_SA_DQS_DN<5>")
	)
	(segment
		(start 86.65718 -276.21865)
		(end 86.659466 -276.220174)
		(width 0.088646)
		(layer "In2.Cu")
		(net "M_B_CPU1_SA_DQS_DN<5>")
	)
	(segment
		(start 66.0527 -311.09793)
		(end 66.024506 -311.069736)
		(width 0.16002)
		(layer "In2.Cu")
		(net "M_B_CPU1_SA_DQS_DN<5>")
	)
	(segment
		(start 53.903118 -311.442354)
		(end 52.903374 -311.442354)
		(width 0.18288)
		(layer "In2.Cu")
		(net "M_B_CPU1_SA_DQS_DN<5>")
	)
	(segment
		(start 85.029802 -279.280874)
		(end 84.868512 -279.442164)
		(width 0.088646)
		(layer "In2.Cu")
		(net "M_B_CPU1_SA_DQS_DN<5>")
	)
	(segment
		(start 77.518006 -292.36797)
		(end 74.727816 -299.10405)
		(width 0.18288)
		(layer "In2.Cu")
		(net "M_B_CPU1_SA_DQS_DN<5>")
	)
	(segment
		(start 62.161928 -312.15711)
		(end 61.952632 -311.947814)
		(width 0.18288)
		(layer "In2.Cu")
		(net "M_B_CPU1_SA_DQS_DN<5>")
	)
	(segment
		(start 54.380638 -311.903618)
		(end 54.180994 -311.703974)
		(width 0.16002)
		(layer "In2.Cu")
		(net "M_B_CPU1_SA_DQS_DN<5>")
	)
	(segment
		(start 61.952632 -311.947814)
		(end 61.924438 -311.91962)
		(width 0.16002)
		(layer "In2.Cu")
		(net "M_B_CPU1_SA_DQS_DN<5>")
	)
	(segment
		(start 64.069722 -311.05348)
		(end 64.069722 -311.069736)
		(width 0.16002)
		(layer "In2.Cu")
		(net "M_B_CPU1_SA_DQS_DN<5>")
	)
	(segment
		(start 54.408832 -311.948068)
		(end 54.380638 -311.919874)
		(width 0.16002)
		(layer "In2.Cu")
		(net "M_B_CPU1_SA_DQS_DN<5>")
	)
	(segment
		(start 82.676238 -283.854906)
		(end 81.973674 -285.550864)
		(width 0.18288)
		(layer "In2.Cu")
		(net "M_B_CPU1_SA_DQS_DN<5>")
	)
	(segment
		(start 86.375494 -278.901652)
		(end 85.833966 -278.901652)
		(width 0.088646)
		(layer "In2.Cu")
		(net "M_B_CPU1_SA_DQS_DN<5>")
	)
	(segment
		(start 65.673732 -310.718962)
		(end 64.420496 -310.718962)
		(width 0.18288)
		(layer "In2.Cu")
		(net "M_B_CPU1_SA_DQS_DN<5>")
	)
	(segment
		(start 85.454744 -279.280874)
		(end 85.029802 -279.280874)
		(width 0.088646)
		(layer "In2.Cu")
		(net "M_B_CPU1_SA_DQS_DN<5>")
	)
	(segment
		(start 64.313816 -310.825642)
		(end 64.285622 -310.853836)
		(width 0.16002)
		(layer "In2.Cu")
		(net "M_B_CPU1_SA_DQS_DN<5>")
	)
	(segment
		(start 77.823568 -291.630862)
		(end 77.890878 -291.793422)
		(width 0.18288)
		(layer "In2.Cu")
		(net "M_B_CPU1_SA_DQS_DN<5>")
	)
	(segment
		(start 86.657942 -277.847044)
		(end 86.660736 -277.848568)
		(width 0.088646)
		(layer "In2.Cu")
		(net "M_B_CPU1_SA_DQS_DN<5>")
	)
	(segment
		(start 56.30672 -312.432954)
		(end 56.278526 -312.40476)
		(width 0.16002)
		(layer "In2.Cu")
		(net "M_B_CPU1_SA_DQS_DN<5>")
	)
	(segment
		(start 84.868512 -279.527)
		(end 82.859118 -281.536394)
		(width 0.18288)
		(layer "In2.Cu")
		(net "M_B_CPU1_SA_DQS_DN<5>")
	)
	(segment
		(start 86.649052 -276.214078)
		(end 86.65718 -276.21865)
		(width 0.088646)
		(layer "In2.Cu")
		(net "M_B_CPU1_SA_DQS_DN<5>")
	)
	(segment
		(start 86.657942 -275.570442)
		(end 86.649052 -275.575522)
		(width 0.088646)
		(layer "In2.Cu")
		(net "M_B_CPU1_SA_DQS_DN<5>")
	)
	(segment
		(start 51.366166 -311.790334)
		(end 51.089814 -312.066686)
		(width 0.18288)
		(layer "In2.Cu")
		(net "M_B_CPU1_SA_DQS_DN<5>")
	)
	(segment
		(start 59.969654 -311.91962)
		(end 59.94146 -311.947814)
		(width 0.16002)
		(layer "In2.Cu")
		(net "M_B_CPU1_SA_DQS_DN<5>")
	)
	(segment
		(start 85.833966 -278.901652)
		(end 85.454744 -279.280874)
		(width 0.088646)
		(layer "In2.Cu")
		(net "M_B_CPU1_SA_DQS_DN<5>")
	)
	(segment
		(start 54.180994 -311.703974)
		(end 54.164738 -311.703974)
		(width 0.16002)
		(layer "In2.Cu")
		(net "M_B_CPU1_SA_DQS_DN<5>")
	)
	(segment
		(start 52.309268 -312.03646)
		(end 51.769772 -312.03646)
		(width 0.18288)
		(layer "In2.Cu")
		(net "M_B_CPU1_SA_DQS_DN<5>")
	)
	(segment
		(start 52.679854 -311.665874)
		(end 52.663598 -311.665874)
		(width 0.16002)
		(layer "In2.Cu")
		(net "M_B_CPU1_SA_DQS_DN<5>")
	)
	(segment
		(start 65.808606 -310.853836)
		(end 65.780412 -310.825642)
		(width 0.16002)
		(layer "In2.Cu")
		(net "M_B_CPU1_SA_DQS_DN<5>")
	)
	(segment
		(start 58.455814 -312.677048)
		(end 58.258456 -312.874406)
		(width 0.18288)
		(layer "In2.Cu")
		(net "M_B_CPU1_SA_DQS_DN<5>")
	)
	(segment
		(start 52.708048 -311.63768)
		(end 52.679854 -311.665874)
		(width 0.16002)
		(layer "In2.Cu")
		(net "M_B_CPU1_SA_DQS_DN<5>")
	)
	(segment
		(start 86.660736 -276.220936)
		(end 86.664038 -276.222714)
		(width 0.088646)
		(layer "In2.Cu")
		(net "M_B_CPU1_SA_DQS_DN<5>")
	)
	(segment
		(start 78.406244 -290.549584)
		(end 78.196186 -291.056568)
		(width 0.18288)
		(layer "In2.Cu")
		(net "M_B_CPU1_SA_DQS_DN<5>")
	)
	(segment
		(start 61.708538 -311.70372)
		(end 61.680344 -311.675526)
		(width 0.16002)
		(layer "In2.Cu")
		(net "M_B_CPU1_SA_DQS_DN<5>")
	)
	(segment
		(start 60.169298 -311.70372)
		(end 59.969654 -311.903364)
		(width 0.16002)
		(layer "In2.Cu")
		(net "M_B_CPU1_SA_DQS_DN<5>")
	)
	(segment
		(start 81.973674 -285.550864)
		(end 79.188564 -288.336228)
		(width 0.18288)
		(layer "In2.Cu")
		(net "M_B_CPU1_SA_DQS_DN<5>")
	)
	(segment
		(start 52.463954 -311.865518)
		(end 52.463954 -311.881774)
		(width 0.16002)
		(layer "In2.Cu")
		(net "M_B_CPU1_SA_DQS_DN<5>")
	)
	(segment
		(start 56.52262 -312.648854)
		(end 56.52262 -312.633106)
		(width 0.16002)
		(layer "In2.Cu")
		(net "M_B_CPU1_SA_DQS_DN<5>")
	)
	(segment
		(start 64.041528 -311.09793)
		(end 62.982348 -312.15711)
		(width 0.18288)
		(layer "In2.Cu")
		(net "M_B_CPU1_SA_DQS_DN<5>")
	)
	(segment
		(start 66.25209 -311.29732)
		(end 66.0527 -311.09793)
		(width 0.18288)
		(layer "In2.Cu")
		(net "M_B_CPU1_SA_DQS_DN<5>")
	)
	(segment
		(start 64.285622 -310.853836)
		(end 64.269366 -310.853836)
		(width 0.16002)
		(layer "In2.Cu")
		(net "M_B_CPU1_SA_DQS_DN<5>")
	)
	(segment
		(start 60.213748 -311.675526)
		(end 60.185554 -311.70372)
		(width 0.16002)
		(layer "In2.Cu")
		(net "M_B_CPU1_SA_DQS_DN<5>")
	)
	(segment
		(start 64.269366 -310.853836)
		(end 64.069722 -311.05348)
		(width 0.16002)
		(layer "In2.Cu")
		(net "M_B_CPU1_SA_DQS_DN<5>")
	)
	(segment
		(start 67.043554 -311.148984)
		(end 66.685922 -311.29732)
		(width 0.18288)
		(layer "In2.Cu")
		(net "M_B_CPU1_SA_DQS_DN<5>")
	)
	(segment
		(start 82.859118 -281.536394)
		(end 82.859118 -283.413454)
		(width 0.18288)
		(layer "In2.Cu")
		(net "M_B_CPU1_SA_DQS_DN<5>")
	)
	(segment
		(start 86.940136 -275.09978)
		(end 86.94039 -275.099272)
		(width 0.088646)
		(layer "In2.Cu")
		(net "M_B_CPU1_SA_DQS_DN<5>")
	)
	(segment
		(start 61.924438 -311.91962)
		(end 61.924438 -311.903364)
		(width 0.16002)
		(layer "In2.Cu")
		(net "M_B_CPU1_SA_DQS_DN<5>")
	)
	(segment
		(start 86.660736 -277.848568)
		(end 86.664038 -277.8506)
		(width 0.088646)
		(layer "In2.Cu")
		(net "M_B_CPU1_SA_DQS_DN<5>")
	)
	(segment
		(start 86.940644 -276.708616)
		(end 86.940644 -276.72284)
		(width 0.088646)
		(layer "In2.Cu")
		(net "M_B_CPU1_SA_DQS_DN<5>")
	)
	(segment
		(start 64.069722 -311.069736)
		(end 64.041528 -311.09793)
		(width 0.16002)
		(layer "In2.Cu")
		(net "M_B_CPU1_SA_DQS_DN<5>")
	)
	(segment
		(start 60.185554 -311.70372)
		(end 60.169298 -311.70372)
		(width 0.16002)
		(layer "In2.Cu")
		(net "M_B_CPU1_SA_DQS_DN<5>")
	)
	(segment
		(start 86.649052 -277.841964)
		(end 86.656418 -277.846282)
		(width 0.088646)
		(layer "In2.Cu")
		(net "M_B_CPU1_SA_DQS_DN<5>")
	)
	(segment
		(start 78.033372 -291.124132)
		(end 77.823568 -291.630862)
		(width 0.18288)
		(layer "In2.Cu")
		(net "M_B_CPU1_SA_DQS_DN<5>")
	)
	(segment
		(start 56.52262 -312.633106)
		(end 56.322468 -312.432954)
		(width 0.16002)
		(layer "In2.Cu")
		(net "M_B_CPU1_SA_DQS_DN<5>")
	)
	(segment
		(start 54.136544 -311.67578)
		(end 53.903118 -311.442354)
		(width 0.18288)
		(layer "In2.Cu")
		(net "M_B_CPU1_SA_DQS_DN<5>")
	)
	(segment
		(start 78.338934 -290.387024)
		(end 78.406244 -290.549584)
		(width 0.18288)
		(layer "In2.Cu")
		(net "M_B_CPU1_SA_DQS_DN<5>")
	)
	(segment
		(start 64.420496 -310.718962)
		(end 64.313816 -310.825642)
		(width 0.18288)
		(layer "In2.Cu")
		(net "M_B_CPU1_SA_DQS_DN<5>")
	)
	(segment
		(start 60.320428 -311.568846)
		(end 60.213748 -311.675526)
		(width 0.18288)
		(layer "In2.Cu")
		(net "M_B_CPU1_SA_DQS_DN<5>")
	)
	(segment
		(start 54.676294 -312.21553)
		(end 54.408832 -311.948068)
		(width 0.18288)
		(layer "In2.Cu")
		(net "M_B_CPU1_SA_DQS_DN<5>")
	)
	(arc
		(start 86.94039 -275.099272)
		(mid 86.860228 -275.371461)
		(end 86.657942 -275.570442)
		(width 0.088646)
		(layer "In2.Cu")
		(net "M_B_CPU1_SA_DQS_DN<5>")
	)
	(arc
		(start 86.940644 -276.72284)
		(mid 86.861425 -276.997525)
		(end 86.657942 -277.198328)
		(width 0.088646)
		(layer "In2.Cu")
		(net "M_B_CPU1_SA_DQS_DN<5>")
	)
	(arc
		(start 86.649052 -277.203408)
		(mid 86.470334 -277.522686)
		(end 86.649052 -277.841964)
		(width 0.088646)
		(layer "In2.Cu")
		(net "M_B_CPU1_SA_DQS_DN<5>")
	)
	(arc
		(start 87.127842 -274.756372)
		(mid 86.991729 -274.891185)
		(end 86.940136 -275.07565)
		(width 0.088646)
		(layer "In2.Cu")
		(net "M_B_CPU1_SA_DQS_DN<5>")
	)
	(arc
		(start 89.007696 -274.756372)
		(mid 88.724994 -274.832148)
		(end 88.442292 -274.756372)
		(width 0.088646)
		(layer "In2.Cu")
		(net "M_B_CPU1_SA_DQS_DN<5>")
	)
	(arc
		(start 89.947496 -274.756372)
		(mid 89.664794 -274.832148)
		(end 89.382092 -274.756372)
		(width 0.088646)
		(layer "In2.Cu")
		(net "M_B_CPU1_SA_DQS_DN<5>")
	)
	(arc
		(start 88.057482 -274.762468)
		(mid 87.77905 -274.832314)
		(end 87.502238 -274.756372)
		(width 0.088646)
		(layer "In2.Cu")
		(net "M_B_CPU1_SA_DQS_DN<5>")
	)
	(arc
		(start 87.502238 -274.756372)
		(mid 87.31504 -274.706229)
		(end 87.127842 -274.756372)
		(width 0.088646)
		(layer "In2.Cu")
		(net "M_B_CPU1_SA_DQS_DN<5>")
	)
	(arc
		(start 90.504772 -275.023326)
		(mid 90.296489 -274.74298)
		(end 89.947496 -274.756372)
		(width 0.088646)
		(layer "In2.Cu")
		(net "M_B_CPU1_SA_DQS_DN<5>")
	)
	(arc
		(start 86.664038 -277.8506)
		(mid 86.920573 -278.486095)
		(end 86.375494 -278.901652)
		(width 0.088646)
		(layer "In2.Cu")
		(net "M_B_CPU1_SA_DQS_DN<5>")
	)
	(arc
		(start 88.442292 -274.756372)
		(mid 88.255094 -274.706229)
		(end 88.067896 -274.756372)
		(width 0.088646)
		(layer "In2.Cu")
		(net "M_B_CPU1_SA_DQS_DN<5>")
	)
	(arc
		(start 86.664038 -276.222714)
		(mid 86.866625 -276.429065)
		(end 86.940644 -276.708616)
		(width 0.088646)
		(layer "In2.Cu")
		(net "M_B_CPU1_SA_DQS_DN<5>")
	)
	(arc
		(start 89.382092 -274.756372)
		(mid 89.194894 -274.706229)
		(end 89.007696 -274.756372)
		(width 0.088646)
		(layer "In2.Cu")
		(net "M_B_CPU1_SA_DQS_DN<5>")
	)
	(arc
		(start 86.649052 -275.575522)
		(mid 86.470576 -275.8948)
		(end 86.649052 -276.214078)
		(width 0.088646)
		(layer "In2.Cu")
		(net "M_B_CPU1_SA_DQS_DN<5>")
	)
	(segment
		(start 43.77182 -275.091652)
		(end 43.616626 -275.091652)
		(width 0.20066)
		(layer "F.Cu")
		(net "M_B_CPU1_SA_DQS_DN<4>")
	)
	(segment
		(start 39.63924 -274.927822)
		(end 39.125398 -274.927822)
		(width 0.20066)
		(layer "F.Cu")
		(net "M_B_CPU1_SA_DQS_DN<4>")
	)
	(segment
		(start 41.292272 -275.080984)
		(end 41.29151 -275.080984)
		(width 0.101854)
		(layer "F.Cu")
		(net "M_B_CPU1_SA_DQS_DN<4>")
	)
	(segment
		(start 44.645072 -274.927822)
		(end 44.219876 -275.353018)
		(width 0.20066)
		(layer "F.Cu")
		(net "M_B_CPU1_SA_DQS_DN<4>")
	)
	(segment
		(start 46.964346 -274.66671)
		(end 45.859446 -274.66671)
		(width 0.20066)
		(layer "F.Cu")
		(net "M_B_CPU1_SA_DQS_DN<4>")
	)
	(segment
		(start 38.864286 -274.66671)
		(end 38.315646 -274.66671)
		(width 0.20066)
		(layer "F.Cu")
		(net "M_B_CPU1_SA_DQS_DN<4>")
	)
	(segment
		(start 40.275256 -275.353018)
		(end 39.63924 -274.927822)
		(width 0.20066)
		(layer "F.Cu")
		(net "M_B_CPU1_SA_DQS_DN<4>")
	)
	(segment
		(start 43.616626 -275.091652)
		(end 41.30294 -275.091652)
		(width 0.1016)
		(layer "F.Cu")
		(net "M_B_CPU1_SA_DQS_DN<4>")
	)
	(segment
		(start 41.29151 -275.080984)
		(end 41.087294 -275.080984)
		(width 0.20066)
		(layer "F.Cu")
		(net "M_B_CPU1_SA_DQS_DN<4>")
	)
	(segment
		(start 40.81526 -275.353018)
		(end 40.275256 -275.353018)
		(width 0.20066)
		(layer "F.Cu")
		(net "M_B_CPU1_SA_DQS_DN<4>")
	)
	(segment
		(start 41.087294 -275.080984)
		(end 40.81526 -275.353018)
		(width 0.20066)
		(layer "F.Cu")
		(net "M_B_CPU1_SA_DQS_DN<4>")
	)
	(segment
		(start 44.033186 -275.353018)
		(end 43.77182 -275.091652)
		(width 0.20066)
		(layer "F.Cu")
		(net "M_B_CPU1_SA_DQS_DN<4>")
	)
	(segment
		(start 45.859446 -274.66671)
		(end 45.312838 -274.66671)
		(width 0.20066)
		(layer "F.Cu")
		(net "M_B_CPU1_SA_DQS_DN<4>")
	)
	(segment
		(start 45.051726 -274.927822)
		(end 44.645072 -274.927822)
		(width 0.20066)
		(layer "F.Cu")
		(net "M_B_CPU1_SA_DQS_DN<4>")
	)
	(segment
		(start 41.30294 -275.091652)
		(end 41.292272 -275.080984)
		(width 0.101854)
		(layer "F.Cu")
		(net "M_B_CPU1_SA_DQS_DN<4>")
	)
	(segment
		(start 45.312838 -274.66671)
		(end 45.051726 -274.927822)
		(width 0.20066)
		(layer "F.Cu")
		(net "M_B_CPU1_SA_DQS_DN<4>")
	)
	(segment
		(start 39.125398 -274.927822)
		(end 38.864286 -274.66671)
		(width 0.20066)
		(layer "F.Cu")
		(net "M_B_CPU1_SA_DQS_DN<4>")
	)
	(segment
		(start 88.255094 -259.894832)
		(end 88.255094 -260.430772)
		(width 0.20066)
		(layer "F.Cu")
		(net "M_B_CPU1_SA_DQS_DN<4>")
	)
	(segment
		(start 44.219876 -275.353018)
		(end 44.033186 -275.353018)
		(width 0.20066)
		(layer "F.Cu")
		(net "M_B_CPU1_SA_DQS_DN<4>")
	)
	(segment
		(start 49.516538 -275.353018)
		(end 49.358296 -275.194776)
		(width 0.18288)
		(layer "In2.Cu")
		(net "M_B_CPU1_SA_DQS_DN<4>")
	)
	(segment
		(start 70.479412 -269.476728)
		(end 70.30339 -269.476728)
		(width 0.18288)
		(layer "In2.Cu")
		(net "M_B_CPU1_SA_DQS_DN<4>")
	)
	(segment
		(start 54.038754 -275.99513)
		(end 52.767738 -275.99513)
		(width 0.18288)
		(layer "In2.Cu")
		(net "M_B_CPU1_SA_DQS_DN<4>")
	)
	(segment
		(start 67.059302 -272.720816)
		(end 67.059302 -272.896838)
		(width 0.18288)
		(layer "In2.Cu")
		(net "M_B_CPU1_SA_DQS_DN<4>")
	)
	(segment
		(start 49.114202 -274.950682)
		(end 49.086008 -274.922488)
		(width 0.16002)
		(layer "In2.Cu")
		(net "M_B_CPU1_SA_DQS_DN<4>")
	)
	(segment
		(start 71.819262 -267.960856)
		(end 71.819262 -268.136878)
		(width 0.18288)
		(layer "In2.Cu")
		(net "M_B_CPU1_SA_DQS_DN<4>")
	)
	(segment
		(start 56.658002 -274.951698)
		(end 56.658002 -274.935442)
		(width 0.16002)
		(layer "In2.Cu")
		(net "M_B_CPU1_SA_DQS_DN<4>")
	)
	(segment
		(start 57.084214 -275.361654)
		(end 56.902096 -275.179536)
		(width 0.18288)
		(layer "In2.Cu")
		(net "M_B_CPU1_SA_DQS_DN<4>")
	)
	(segment
		(start 66.114168 -273.323558)
		(end 66.09842 -273.323558)
		(width 0.16002)
		(layer "In2.Cu")
		(net "M_B_CPU1_SA_DQS_DN<4>")
	)
	(segment
		(start 49.358296 -275.194776)
		(end 49.330102 -275.166582)
		(width 0.16002)
		(layer "In2.Cu")
		(net "M_B_CPU1_SA_DQS_DN<4>")
	)
	(segment
		(start 87.128096 -260.755384)
		(end 87.128096 -260.75513)
		(width 0.088646)
		(layer "In2.Cu")
		(net "M_B_CPU1_SA_DQS_DN<4>")
	)
	(segment
		(start 49.086008 -274.922488)
		(end 48.82007 -274.65655)
		(width 0.18288)
		(layer "In2.Cu")
		(net "M_B_CPU1_SA_DQS_DN<4>")
	)
	(segment
		(start 49.313846 -275.166582)
		(end 49.114202 -274.966938)
		(width 0.16002)
		(layer "In2.Cu")
		(net "M_B_CPU1_SA_DQS_DN<4>")
	)
	(segment
		(start 63.867792 -273.391884)
		(end 63.389764 -273.87042)
		(width 0.18288)
		(layer "In2.Cu")
		(net "M_B_CPU1_SA_DQS_DN<4>")
	)
	(segment
		(start 56.658002 -274.935442)
		(end 56.629808 -274.907248)
		(width 0.16002)
		(layer "In2.Cu")
		(net "M_B_CPU1_SA_DQS_DN<4>")
	)
	(segment
		(start 59.94908 -275.632672)
		(end 59.678062 -275.361654)
		(width 0.18288)
		(layer "In2.Cu")
		(net "M_B_CPU1_SA_DQS_DN<4>")
	)
	(segment
		(start 65.61328 -272.82267)
		(end 64.437006 -272.82267)
		(width 0.18288)
		(layer "In2.Cu")
		(net "M_B_CPU1_SA_DQS_DN<4>")
	)
	(segment
		(start 77.538326 -264.09523)
		(end 74.675238 -265.280902)
		(width 0.18288)
		(layer "In2.Cu")
		(net "M_B_CPU1_SA_DQS_DN<4>")
	)
	(segment
		(start 88.071198 -260.614668)
		(end 88.027256 -260.614668)
		(width 0.088646)
		(layer "In2.Cu")
		(net "M_B_CPU1_SA_DQS_DN<4>")
	)
	(segment
		(start 64.437006 -272.82267)
		(end 64.13754 -273.122136)
		(width 0.18288)
		(layer "In2.Cu")
		(net "M_B_CPU1_SA_DQS_DN<4>")
	)
	(segment
		(start 61.945012 -275.632672)
		(end 61.916818 -275.660866)
		(width 0.16002)
		(layer "In2.Cu")
		(net "M_B_CPU1_SA_DQS_DN<4>")
	)
	(segment
		(start 61.557662 -276.020022)
		(end 60.33643 -276.020022)
		(width 0.18288)
		(layer "In2.Cu")
		(net "M_B_CPU1_SA_DQS_DN<4>")
	)
	(segment
		(start 59.678062 -275.361654)
		(end 59.056778 -275.361654)
		(width 0.18288)
		(layer "In2.Cu")
		(net "M_B_CPU1_SA_DQS_DN<4>")
	)
	(segment
		(start 68.399406 -271.380712)
		(end 68.011294 -271.768824)
		(width 0.18288)
		(layer "In2.Cu")
		(net "M_B_CPU1_SA_DQS_DN<4>")
	)
	(segment
		(start 61.916818 -275.677122)
		(end 61.717174 -275.876766)
		(width 0.16002)
		(layer "In2.Cu")
		(net "M_B_CPU1_SA_DQS_DN<4>")
	)
	(segment
		(start 64.109346 -273.166078)
		(end 63.911734 -273.36369)
		(width 0.16002)
		(layer "In2.Cu")
		(net "M_B_CPU1_SA_DQS_DN<4>")
	)
	(segment
		(start 61.700918 -275.876766)
		(end 61.672724 -275.90496)
		(width 0.16002)
		(layer "In2.Cu")
		(net "M_B_CPU1_SA_DQS_DN<4>")
	)
	(segment
		(start 64.13754 -273.122136)
		(end 64.109346 -273.15033)
		(width 0.16002)
		(layer "In2.Cu")
		(net "M_B_CPU1_SA_DQS_DN<4>")
	)
	(segment
		(start 69.52742 -270.42872)
		(end 69.351398 -270.42872)
		(width 0.18288)
		(layer "In2.Cu")
		(net "M_B_CPU1_SA_DQS_DN<4>")
	)
	(segment
		(start 52.121816 -275.349208)
		(end 51.516788 -275.349208)
		(width 0.18288)
		(layer "In2.Cu")
		(net "M_B_CPU1_SA_DQS_DN<4>")
	)
	(segment
		(start 68.963286 -270.816832)
		(end 68.963286 -270.992854)
		(width 0.18288)
		(layer "In2.Cu")
		(net "M_B_CPU1_SA_DQS_DN<4>")
	)
	(segment
		(start 52.677568 -275.90496)
		(end 52.649374 -275.876766)
		(width 0.16002)
		(layer "In2.Cu")
		(net "M_B_CPU1_SA_DQS_DN<4>")
	)
	(segment
		(start 54.373018 -275.677122)
		(end 54.173374 -275.876766)
		(width 0.16002)
		(layer "In2.Cu")
		(net "M_B_CPU1_SA_DQS_DN<4>")
	)
	(segment
		(start 70.86727 -268.912848)
		(end 70.86727 -269.08887)
		(width 0.18288)
		(layer "In2.Cu")
		(net "M_B_CPU1_SA_DQS_DN<4>")
	)
	(segment
		(start 72.771254 -267.184886)
		(end 72.383396 -267.572744)
		(width 0.18288)
		(layer "In2.Cu")
		(net "M_B_CPU1_SA_DQS_DN<4>")
	)
	(segment
		(start 61.672724 -275.90496)
		(end 61.557662 -276.020022)
		(width 0.18288)
		(layer "In2.Cu")
		(net "M_B_CPU1_SA_DQS_DN<4>")
	)
	(segment
		(start 73.723246 -266.056872)
		(end 73.723246 -266.232894)
		(width 0.18288)
		(layer "In2.Cu")
		(net "M_B_CPU1_SA_DQS_DN<4>")
	)
	(segment
		(start 72.383396 -267.572744)
		(end 72.207374 -267.572744)
		(width 0.18288)
		(layer "In2.Cu")
		(net "M_B_CPU1_SA_DQS_DN<4>")
	)
	(segment
		(start 52.649374 -275.876766)
		(end 52.633118 -275.876766)
		(width 0.16002)
		(layer "In2.Cu")
		(net "M_B_CPU1_SA_DQS_DN<4>")
	)
	(segment
		(start 61.717174 -275.876766)
		(end 61.700918 -275.876766)
		(width 0.16002)
		(layer "In2.Cu")
		(net "M_B_CPU1_SA_DQS_DN<4>")
	)
	(segment
		(start 54.173374 -275.876766)
		(end 54.157118 -275.876766)
		(width 0.16002)
		(layer "In2.Cu")
		(net "M_B_CPU1_SA_DQS_DN<4>")
	)
	(segment
		(start 55.259478 -275.347176)
		(end 54.686708 -275.347176)
		(width 0.18288)
		(layer "In2.Cu")
		(net "M_B_CPU1_SA_DQS_DN<4>")
	)
	(segment
		(start 56.629808 -274.907248)
		(end 56.44007 -274.71751)
		(width 0.18288)
		(layer "In2.Cu")
		(net "M_B_CPU1_SA_DQS_DN<4>")
	)
	(segment
		(start 67.447414 -272.332704)
		(end 67.059302 -272.720816)
		(width 0.18288)
		(layer "In2.Cu")
		(net "M_B_CPU1_SA_DQS_DN<4>")
	)
	(segment
		(start 74.28738 -265.66876)
		(end 74.111358 -265.66876)
		(width 0.18288)
		(layer "In2.Cu")
		(net "M_B_CPU1_SA_DQS_DN<4>")
	)
	(segment
		(start 71.255382 -268.524736)
		(end 70.86727 -268.912848)
		(width 0.18288)
		(layer "In2.Cu")
		(net "M_B_CPU1_SA_DQS_DN<4>")
	)
	(segment
		(start 78.92923 -262.704326)
		(end 77.538326 -264.09523)
		(width 0.18288)
		(layer "In2.Cu")
		(net "M_B_CPU1_SA_DQS_DN<4>")
	)
	(segment
		(start 73.335388 -266.620752)
		(end 73.159366 -266.620752)
		(width 0.18288)
		(layer "In2.Cu")
		(net "M_B_CPU1_SA_DQS_DN<4>")
	)
	(segment
		(start 48.044862 -274.65655)
		(end 47.717202 -274.98421)
		(width 0.18288)
		(layer "In2.Cu")
		(net "M_B_CPU1_SA_DQS_DN<4>")
	)
	(segment
		(start 62.82563 -274.434808)
		(end 62.438026 -274.822666)
		(width 0.18288)
		(layer "In2.Cu")
		(net "M_B_CPU1_SA_DQS_DN<4>")
	)
	(segment
		(start 60.193174 -275.876766)
		(end 60.176918 -275.876766)
		(width 0.16002)
		(layer "In2.Cu")
		(net "M_B_CPU1_SA_DQS_DN<4>")
	)
	(segment
		(start 66.142362 -273.351752)
		(end 66.114168 -273.323558)
		(width 0.16002)
		(layer "In2.Cu")
		(net "M_B_CPU1_SA_DQS_DN<4>")
	)
	(segment
		(start 64.109346 -273.15033)
		(end 64.109346 -273.166078)
		(width 0.16002)
		(layer "In2.Cu")
		(net "M_B_CPU1_SA_DQS_DN<4>")
	)
	(segment
		(start 74.675238 -265.280902)
		(end 74.28738 -265.66876)
		(width 0.18288)
		(layer "In2.Cu")
		(net "M_B_CPU1_SA_DQS_DN<4>")
	)
	(segment
		(start 67.059302 -272.896838)
		(end 66.51879 -273.43735)
		(width 0.18288)
		(layer "In2.Cu")
		(net "M_B_CPU1_SA_DQS_DN<4>")
	)
	(segment
		(start 69.915278 -270.040862)
		(end 69.52742 -270.42872)
		(width 0.18288)
		(layer "In2.Cu")
		(net "M_B_CPU1_SA_DQS_DN<4>")
	)
	(segment
		(start 68.011294 -271.768824)
		(end 68.011294 -271.944846)
		(width 0.18288)
		(layer "In2.Cu")
		(net "M_B_CPU1_SA_DQS_DN<4>")
	)
	(segment
		(start 56.857646 -275.151342)
		(end 56.658002 -274.951698)
		(width 0.16002)
		(layer "In2.Cu")
		(net "M_B_CPU1_SA_DQS_DN<4>")
	)
	(segment
		(start 83.631024 -260.679438)
		(end 81.769966 -262.540242)
		(width 0.088646)
		(layer "In2.Cu")
		(net "M_B_CPU1_SA_DQS_DN<4>")
	)
	(segment
		(start 52.433474 -275.677122)
		(end 52.433474 -275.660866)
		(width 0.16002)
		(layer "In2.Cu")
		(net "M_B_CPU1_SA_DQS_DN<4>")
	)
	(segment
		(start 72.771254 -267.008864)
		(end 72.771254 -267.184886)
		(width 0.18288)
		(layer "In2.Cu")
		(net "M_B_CPU1_SA_DQS_DN<4>")
	)
	(segment
		(start 69.351398 -270.42872)
		(end 68.963286 -270.816832)
		(width 0.18288)
		(layer "In2.Cu")
		(net "M_B_CPU1_SA_DQS_DN<4>")
	)
	(segment
		(start 66.22796 -273.43735)
		(end 66.142362 -273.351752)
		(width 0.18288)
		(layer "In2.Cu")
		(net "M_B_CPU1_SA_DQS_DN<4>")
	)
	(segment
		(start 52.40528 -275.632672)
		(end 52.121816 -275.349208)
		(width 0.18288)
		(layer "In2.Cu")
		(net "M_B_CPU1_SA_DQS_DN<4>")
	)
	(segment
		(start 52.433474 -275.660866)
		(end 52.40528 -275.632672)
		(width 0.16002)
		(layer "In2.Cu")
		(net "M_B_CPU1_SA_DQS_DN<4>")
	)
	(segment
		(start 73.723246 -266.232894)
		(end 73.335388 -266.620752)
		(width 0.18288)
		(layer "In2.Cu")
		(net "M_B_CPU1_SA_DQS_DN<4>")
	)
	(segment
		(start 56.873902 -275.151342)
		(end 56.857646 -275.151342)
		(width 0.16002)
		(layer "In2.Cu")
		(net "M_B_CPU1_SA_DQS_DN<4>")
	)
	(segment
		(start 88.255094 -260.430772)
		(end 88.071198 -260.614668)
		(width 0.088646)
		(layer "In2.Cu")
		(net "M_B_CPU1_SA_DQS_DN<4>")
	)
	(segment
		(start 62.213236 -275.364448)
		(end 61.945012 -275.632672)
		(width 0.18288)
		(layer "In2.Cu")
		(net "M_B_CPU1_SA_DQS_DN<4>")
	)
	(segment
		(start 81.769966 -262.540242)
		(end 81.374488 -262.704326)
		(width 0.088646)
		(layer "In2.Cu")
		(net "M_B_CPU1_SA_DQS_DN<4>")
	)
	(segment
		(start 68.575428 -271.380712)
		(end 68.399406 -271.380712)
		(width 0.18288)
		(layer "In2.Cu")
		(net "M_B_CPU1_SA_DQS_DN<4>")
	)
	(segment
		(start 50.869596 -275.091652)
		(end 50.60823 -275.353018)
		(width 0.18288)
		(layer "In2.Cu")
		(net "M_B_CPU1_SA_DQS_DN<4>")
	)
	(segment
		(start 54.401212 -275.632672)
		(end 54.373018 -275.660866)
		(width 0.16002)
		(layer "In2.Cu")
		(net "M_B_CPU1_SA_DQS_DN<4>")
	)
	(segment
		(start 63.213742 -273.87042)
		(end 62.82563 -274.258786)
		(width 0.18288)
		(layer "In2.Cu")
		(net "M_B_CPU1_SA_DQS_DN<4>")
	)
	(segment
		(start 74.111358 -265.66876)
		(end 73.723246 -266.056872)
		(width 0.18288)
		(layer "In2.Cu")
		(net "M_B_CPU1_SA_DQS_DN<4>")
	)
	(segment
		(start 60.221368 -275.90496)
		(end 60.193174 -275.876766)
		(width 0.16002)
		(layer "In2.Cu")
		(net "M_B_CPU1_SA_DQS_DN<4>")
	)
	(segment
		(start 73.159366 -266.620752)
		(end 72.771254 -267.008864)
		(width 0.18288)
		(layer "In2.Cu")
		(net "M_B_CPU1_SA_DQS_DN<4>")
	)
	(segment
		(start 68.963286 -270.992854)
		(end 68.575428 -271.380712)
		(width 0.18288)
		(layer "In2.Cu")
		(net "M_B_CPU1_SA_DQS_DN<4>")
	)
	(segment
		(start 81.022698 -262.704326)
		(end 78.92923 -262.704326)
		(width 0.18288)
		(layer "In2.Cu")
		(net "M_B_CPU1_SA_DQS_DN<4>")
	)
	(segment
		(start 63.389764 -273.87042)
		(end 63.213742 -273.87042)
		(width 0.18288)
		(layer "In2.Cu")
		(net "M_B_CPU1_SA_DQS_DN<4>")
	)
	(segment
		(start 49.330102 -275.166582)
		(end 49.313846 -275.166582)
		(width 0.16002)
		(layer "In2.Cu")
		(net "M_B_CPU1_SA_DQS_DN<4>")
	)
	(segment
		(start 55.889144 -274.71751)
		(end 55.259478 -275.347176)
		(width 0.18288)
		(layer "In2.Cu")
		(net "M_B_CPU1_SA_DQS_DN<4>")
	)
	(segment
		(start 63.895986 -273.36369)
		(end 63.867792 -273.391884)
		(width 0.16002)
		(layer "In2.Cu")
		(net "M_B_CPU1_SA_DQS_DN<4>")
	)
	(segment
		(start 59.977274 -275.677122)
		(end 59.977274 -275.660866)
		(width 0.16002)
		(layer "In2.Cu")
		(net "M_B_CPU1_SA_DQS_DN<4>")
	)
	(segment
		(start 60.33643 -276.020022)
		(end 60.221368 -275.90496)
		(width 0.18288)
		(layer "In2.Cu")
		(net "M_B_CPU1_SA_DQS_DN<4>")
	)
	(segment
		(start 62.438026 -274.822666)
		(end 62.213236 -275.364448)
		(width 0.18288)
		(layer "In2.Cu")
		(net "M_B_CPU1_SA_DQS_DN<4>")
	)
	(segment
		(start 54.686708 -275.347176)
		(end 54.401212 -275.632672)
		(width 0.18288)
		(layer "In2.Cu")
		(net "M_B_CPU1_SA_DQS_DN<4>")
	)
	(segment
		(start 58.784998 -275.089874)
		(end 58.43143 -275.089874)
		(width 0.18288)
		(layer "In2.Cu")
		(net "M_B_CPU1_SA_DQS_DN<4>")
	)
	(segment
		(start 54.373018 -275.660866)
		(end 54.373018 -275.677122)
		(width 0.16002)
		(layer "In2.Cu")
		(net "M_B_CPU1_SA_DQS_DN<4>")
	)
	(segment
		(start 68.011294 -271.944846)
		(end 67.623436 -272.332704)
		(width 0.18288)
		(layer "In2.Cu")
		(net "M_B_CPU1_SA_DQS_DN<4>")
	)
	(segment
		(start 50.60823 -275.353018)
		(end 49.516538 -275.353018)
		(width 0.18288)
		(layer "In2.Cu")
		(net "M_B_CPU1_SA_DQS_DN<4>")
	)
	(segment
		(start 58.15965 -275.361654)
		(end 57.084214 -275.361654)
		(width 0.18288)
		(layer "In2.Cu")
		(net "M_B_CPU1_SA_DQS_DN<4>")
	)
	(segment
		(start 71.431404 -268.524736)
		(end 71.255382 -268.524736)
		(width 0.18288)
		(layer "In2.Cu")
		(net "M_B_CPU1_SA_DQS_DN<4>")
	)
	(segment
		(start 51.259232 -275.091652)
		(end 50.869596 -275.091652)
		(width 0.18288)
		(layer "In2.Cu")
		(net "M_B_CPU1_SA_DQS_DN<4>")
	)
	(segment
		(start 70.30339 -269.476728)
		(end 69.915278 -269.86484)
		(width 0.18288)
		(layer "In2.Cu")
		(net "M_B_CPU1_SA_DQS_DN<4>")
	)
	(segment
		(start 63.911734 -273.36369)
		(end 63.895986 -273.36369)
		(width 0.16002)
		(layer "In2.Cu")
		(net "M_B_CPU1_SA_DQS_DN<4>")
	)
	(segment
		(start 56.902096 -275.179536)
		(end 56.873902 -275.151342)
		(width 0.16002)
		(layer "In2.Cu")
		(net "M_B_CPU1_SA_DQS_DN<4>")
	)
	(segment
		(start 59.056778 -275.361654)
		(end 58.784998 -275.089874)
		(width 0.18288)
		(layer "In2.Cu")
		(net "M_B_CPU1_SA_DQS_DN<4>")
	)
	(segment
		(start 54.128924 -275.90496)
		(end 54.038754 -275.99513)
		(width 0.18288)
		(layer "In2.Cu")
		(net "M_B_CPU1_SA_DQS_DN<4>")
	)
	(segment
		(start 69.915278 -269.86484)
		(end 69.915278 -270.040862)
		(width 0.18288)
		(layer "In2.Cu")
		(net "M_B_CPU1_SA_DQS_DN<4>")
	)
	(segment
		(start 81.374488 -262.704326)
		(end 81.022698 -262.704326)
		(width 0.088646)
		(layer "In2.Cu")
		(net "M_B_CPU1_SA_DQS_DN<4>")
	)
	(segment
		(start 52.767738 -275.99513)
		(end 52.677568 -275.90496)
		(width 0.18288)
		(layer "In2.Cu")
		(net "M_B_CPU1_SA_DQS_DN<4>")
	)
	(segment
		(start 48.82007 -274.65655)
		(end 48.044862 -274.65655)
		(width 0.18288)
		(layer "In2.Cu")
		(net "M_B_CPU1_SA_DQS_DN<4>")
	)
	(segment
		(start 54.157118 -275.876766)
		(end 54.128924 -275.90496)
		(width 0.16002)
		(layer "In2.Cu")
		(net "M_B_CPU1_SA_DQS_DN<4>")
	)
	(segment
		(start 65.898268 -273.123406)
		(end 65.898268 -273.107658)
		(width 0.16002)
		(layer "In2.Cu")
		(net "M_B_CPU1_SA_DQS_DN<4>")
	)
	(segment
		(start 66.51879 -273.43735)
		(end 66.22796 -273.43735)
		(width 0.18288)
		(layer "In2.Cu")
		(net "M_B_CPU1_SA_DQS_DN<4>")
	)
	(segment
		(start 47.717202 -274.98421)
		(end 47.281846 -274.98421)
		(width 0.18288)
		(layer "In2.Cu")
		(net "M_B_CPU1_SA_DQS_DN<4>")
	)
	(segment
		(start 71.819262 -268.136878)
		(end 71.431404 -268.524736)
		(width 0.18288)
		(layer "In2.Cu")
		(net "M_B_CPU1_SA_DQS_DN<4>")
	)
	(segment
		(start 60.176918 -275.876766)
		(end 59.977274 -275.677122)
		(width 0.16002)
		(layer "In2.Cu")
		(net "M_B_CPU1_SA_DQS_DN<4>")
	)
	(segment
		(start 66.09842 -273.323558)
		(end 65.898268 -273.123406)
		(width 0.16002)
		(layer "In2.Cu")
		(net "M_B_CPU1_SA_DQS_DN<4>")
	)
	(segment
		(start 67.623436 -272.332704)
		(end 67.447414 -272.332704)
		(width 0.18288)
		(layer "In2.Cu")
		(net "M_B_CPU1_SA_DQS_DN<4>")
	)
	(segment
		(start 61.916818 -275.660866)
		(end 61.916818 -275.677122)
		(width 0.16002)
		(layer "In2.Cu")
		(net "M_B_CPU1_SA_DQS_DN<4>")
	)
	(segment
		(start 65.898268 -273.107658)
		(end 65.870074 -273.079464)
		(width 0.16002)
		(layer "In2.Cu")
		(net "M_B_CPU1_SA_DQS_DN<4>")
	)
	(segment
		(start 72.207374 -267.572744)
		(end 71.819262 -267.960856)
		(width 0.18288)
		(layer "In2.Cu")
		(net "M_B_CPU1_SA_DQS_DN<4>")
	)
	(segment
		(start 59.977274 -275.660866)
		(end 59.94908 -275.632672)
		(width 0.16002)
		(layer "In2.Cu")
		(net "M_B_CPU1_SA_DQS_DN<4>")
	)
	(segment
		(start 70.86727 -269.08887)
		(end 70.479412 -269.476728)
		(width 0.18288)
		(layer "In2.Cu")
		(net "M_B_CPU1_SA_DQS_DN<4>")
	)
	(segment
		(start 65.870074 -273.079464)
		(end 65.61328 -272.82267)
		(width 0.18288)
		(layer "In2.Cu")
		(net "M_B_CPU1_SA_DQS_DN<4>")
	)
	(segment
		(start 47.281846 -274.98421)
		(end 46.964346 -274.66671)
		(width 0.18288)
		(layer "In2.Cu")
		(net "M_B_CPU1_SA_DQS_DN<4>")
	)
	(segment
		(start 62.82563 -274.258786)
		(end 62.82563 -274.434808)
		(width 0.18288)
		(layer "In2.Cu")
		(net "M_B_CPU1_SA_DQS_DN<4>")
	)
	(segment
		(start 84.025994 -260.679438)
		(end 83.631024 -260.679438)
		(width 0.088646)
		(layer "In2.Cu")
		(net "M_B_CPU1_SA_DQS_DN<4>")
	)
	(segment
		(start 51.516788 -275.349208)
		(end 51.259232 -275.091652)
		(width 0.18288)
		(layer "In2.Cu")
		(net "M_B_CPU1_SA_DQS_DN<4>")
	)
	(segment
		(start 56.44007 -274.71751)
		(end 55.889144 -274.71751)
		(width 0.18288)
		(layer "In2.Cu")
		(net "M_B_CPU1_SA_DQS_DN<4>")
	)
	(segment
		(start 49.114202 -274.966938)
		(end 49.114202 -274.950682)
		(width 0.16002)
		(layer "In2.Cu")
		(net "M_B_CPU1_SA_DQS_DN<4>")
	)
	(segment
		(start 52.633118 -275.876766)
		(end 52.433474 -275.677122)
		(width 0.16002)
		(layer "In2.Cu")
		(net "M_B_CPU1_SA_DQS_DN<4>")
	)
	(segment
		(start 58.43143 -275.089874)
		(end 58.15965 -275.361654)
		(width 0.18288)
		(layer "In2.Cu")
		(net "M_B_CPU1_SA_DQS_DN<4>")
	)
	(arc
		(start 84.683092 -260.75513)
		(mid 84.495894 -260.805273)
		(end 84.308696 -260.75513)
		(width 0.088646)
		(layer "In2.Cu")
		(net "M_B_CPU1_SA_DQS_DN<4>")
	)
	(arc
		(start 86.188296 -260.75513)
		(mid 85.905594 -260.679388)
		(end 85.622892 -260.75513)
		(width 0.088646)
		(layer "In2.Cu")
		(net "M_B_CPU1_SA_DQS_DN<4>")
	)
	(arc
		(start 85.248496 -260.75513)
		(mid 84.965794 -260.679388)
		(end 84.683092 -260.75513)
		(width 0.088646)
		(layer "In2.Cu")
		(net "M_B_CPU1_SA_DQS_DN<4>")
	)
	(arc
		(start 85.622892 -260.75513)
		(mid 85.435694 -260.805273)
		(end 85.248496 -260.75513)
		(width 0.088646)
		(layer "In2.Cu")
		(net "M_B_CPU1_SA_DQS_DN<4>")
	)
	(arc
		(start 87.502238 -260.755384)
		(mid 87.31515 -260.805527)
		(end 87.128096 -260.755384)
		(width 0.088646)
		(layer "In2.Cu")
		(net "M_B_CPU1_SA_DQS_DN<4>")
	)
	(arc
		(start 87.128096 -260.75513)
		(mid 86.845394 -260.679388)
		(end 86.562692 -260.75513)
		(width 0.088646)
		(layer "In2.Cu")
		(net "M_B_CPU1_SA_DQS_DN<4>")
	)
	(arc
		(start 88.027256 -260.614668)
		(mid 87.755478 -260.65045)
		(end 87.502238 -260.755384)
		(width 0.088646)
		(layer "In2.Cu")
		(net "M_B_CPU1_SA_DQS_DN<4>")
	)
	(arc
		(start 84.308696 -260.75513)
		(mid 84.172326 -260.698677)
		(end 84.025994 -260.679438)
		(width 0.088646)
		(layer "In2.Cu")
		(net "M_B_CPU1_SA_DQS_DN<4>")
	)
	(arc
		(start 86.562692 -260.75513)
		(mid 86.375494 -260.805273)
		(end 86.188296 -260.75513)
		(width 0.088646)
		(layer "In2.Cu")
		(net "M_B_CPU1_SA_DQS_DN<4>")
	)
	(segment
		(start 46.964346 -284.016704)
		(end 45.859446 -284.016704)
		(width 0.20066)
		(layer "F.Cu")
		(net "M_B_CPU1_SA_DQS_DN<3>")
	)
	(segment
		(start 38.864286 -284.016704)
		(end 38.315646 -284.016704)
		(width 0.20066)
		(layer "F.Cu")
		(net "M_B_CPU1_SA_DQS_DN<3>")
	)
	(segment
		(start 40.81526 -284.703012)
		(end 40.275256 -284.703012)
		(width 0.20066)
		(layer "F.Cu")
		(net "M_B_CPU1_SA_DQS_DN<3>")
	)
	(segment
		(start 41.30294 -284.441646)
		(end 41.292272 -284.430978)
		(width 0.101854)
		(layer "F.Cu")
		(net "M_B_CPU1_SA_DQS_DN<3>")
	)
	(segment
		(start 39.125398 -284.277816)
		(end 38.864286 -284.016704)
		(width 0.20066)
		(layer "F.Cu")
		(net "M_B_CPU1_SA_DQS_DN<3>")
	)
	(segment
		(start 44.033186 -284.703012)
		(end 43.77182 -284.441646)
		(width 0.20066)
		(layer "F.Cu")
		(net "M_B_CPU1_SA_DQS_DN<3>")
	)
	(segment
		(start 41.087294 -284.430978)
		(end 40.81526 -284.703012)
		(width 0.20066)
		(layer "F.Cu")
		(net "M_B_CPU1_SA_DQS_DN<3>")
	)
	(segment
		(start 39.63924 -284.277816)
		(end 39.125398 -284.277816)
		(width 0.20066)
		(layer "F.Cu")
		(net "M_B_CPU1_SA_DQS_DN<3>")
	)
	(segment
		(start 40.275256 -284.703012)
		(end 39.63924 -284.277816)
		(width 0.20066)
		(layer "F.Cu")
		(net "M_B_CPU1_SA_DQS_DN<3>")
	)
	(segment
		(start 45.051726 -284.277816)
		(end 44.645072 -284.277816)
		(width 0.20066)
		(layer "F.Cu")
		(net "M_B_CPU1_SA_DQS_DN<3>")
	)
	(segment
		(start 44.219876 -284.703012)
		(end 44.033186 -284.703012)
		(width 0.20066)
		(layer "F.Cu")
		(net "M_B_CPU1_SA_DQS_DN<3>")
	)
	(segment
		(start 44.645072 -284.277816)
		(end 44.219876 -284.703012)
		(width 0.20066)
		(layer "F.Cu")
		(net "M_B_CPU1_SA_DQS_DN<3>")
	)
	(segment
		(start 45.312838 -284.016704)
		(end 45.051726 -284.277816)
		(width 0.20066)
		(layer "F.Cu")
		(net "M_B_CPU1_SA_DQS_DN<3>")
	)
	(segment
		(start 91.544648 -262.87222)
		(end 91.544394 -262.872474)
		(width 0.20066)
		(layer "F.Cu")
		(net "M_B_CPU1_SA_DQS_DN<3>")
	)
	(segment
		(start 45.859446 -284.016704)
		(end 45.312838 -284.016704)
		(width 0.20066)
		(layer "F.Cu")
		(net "M_B_CPU1_SA_DQS_DN<3>")
	)
	(segment
		(start 91.544648 -262.336534)
		(end 91.544648 -262.87222)
		(width 0.20066)
		(layer "F.Cu")
		(net "M_B_CPU1_SA_DQS_DN<3>")
	)
	(segment
		(start 41.292272 -284.430978)
		(end 41.29151 -284.430978)
		(width 0.101854)
		(layer "F.Cu")
		(net "M_B_CPU1_SA_DQS_DN<3>")
	)
	(segment
		(start 43.616626 -284.441646)
		(end 41.30294 -284.441646)
		(width 0.1016)
		(layer "F.Cu")
		(net "M_B_CPU1_SA_DQS_DN<3>")
	)
	(segment
		(start 43.77182 -284.441646)
		(end 43.616626 -284.441646)
		(width 0.20066)
		(layer "F.Cu")
		(net "M_B_CPU1_SA_DQS_DN<3>")
	)
	(segment
		(start 41.29151 -284.430978)
		(end 41.087294 -284.430978)
		(width 0.20066)
		(layer "F.Cu")
		(net "M_B_CPU1_SA_DQS_DN<3>")
	)
	(segment
		(start 55.460138 -282.36672)
		(end 55.109364 -283.213556)
		(width 0.18288)
		(layer "In4.Cu")
		(net "M_B_CPU1_SA_DQS_DN<3>")
	)
	(segment
		(start 60.1853 -280.437082)
		(end 58.198258 -281.26055)
		(width 0.18288)
		(layer "In4.Cu")
		(net "M_B_CPU1_SA_DQS_DN<3>")
	)
	(segment
		(start 75.35418 -266.810236)
		(end 74.966322 -267.198094)
		(width 0.18288)
		(layer "In4.Cu")
		(net "M_B_CPU1_SA_DQS_DN<3>")
	)
	(segment
		(start 74.966322 -267.198094)
		(end 74.7903 -267.198094)
		(width 0.18288)
		(layer "In4.Cu")
		(net "M_B_CPU1_SA_DQS_DN<3>")
	)
	(segment
		(start 65.615566 -274.992592)
		(end 65.48374 -275.138134)
		(width 0.18288)
		(layer "In4.Cu")
		(net "M_B_CPU1_SA_DQS_DN<3>")
	)
	(segment
		(start 65.48374 -275.138134)
		(end 64.63919 -277.176484)
		(width 0.18288)
		(layer "In4.Cu")
		(net "M_B_CPU1_SA_DQS_DN<3>")
	)
	(segment
		(start 74.402188 -267.762228)
		(end 74.01433 -268.150086)
		(width 0.18288)
		(layer "In4.Cu")
		(net "M_B_CPU1_SA_DQS_DN<3>")
	)
	(segment
		(start 82.834226 -263.26846)
		(end 82.783934 -263.26846)
		(width 0.088646)
		(layer "In4.Cu")
		(net "M_B_CPU1_SA_DQS_DN<3>")
	)
	(segment
		(start 55.109364 -283.213556)
		(end 54.74208 -283.58084)
		(width 0.18288)
		(layer "In4.Cu")
		(net "M_B_CPU1_SA_DQS_DN<3>")
	)
	(segment
		(start 71.546212 -270.442182)
		(end 71.546212 -270.618204)
		(width 0.18288)
		(layer "In4.Cu")
		(net "M_B_CPU1_SA_DQS_DN<3>")
	)
	(segment
		(start 50.31486 -284.714696)
		(end 49.692814 -284.09265)
		(width 0.18288)
		(layer "In4.Cu")
		(net "M_B_CPU1_SA_DQS_DN<3>")
	)
	(segment
		(start 73.450196 -268.71422)
		(end 73.062338 -269.102078)
		(width 0.18288)
		(layer "In4.Cu")
		(net "M_B_CPU1_SA_DQS_DN<3>")
	)
	(segment
		(start 89.862406 -263.190736)
		(end 89.851992 -263.196832)
		(width 0.088646)
		(layer "In4.Cu")
		(net "M_B_CPU1_SA_DQS_DN<3>")
	)
	(segment
		(start 50.600102 -284.714696)
		(end 50.31486 -284.714696)
		(width 0.18288)
		(layer "In4.Cu")
		(net "M_B_CPU1_SA_DQS_DN<3>")
	)
	(segment
		(start 77.822552 -264.342118)
		(end 77.646276 -264.342118)
		(width 0.18288)
		(layer "In4.Cu")
		(net "M_B_CPU1_SA_DQS_DN<3>")
	)
	(segment
		(start 69.642228 -272.522188)
		(end 68.438776 -273.72564)
		(width 0.18288)
		(layer "In4.Cu")
		(net "M_B_CPU1_SA_DQS_DN<3>")
	)
	(segment
		(start 51.4858 -284.687264)
		(end 51.33086 -284.532578)
		(width 0.18288)
		(layer "In4.Cu")
		(net "M_B_CPU1_SA_DQS_DN<3>")
	)
	(segment
		(start 70.982332 -271.006062)
		(end 70.59422 -271.394174)
		(width 0.18288)
		(layer "In4.Cu")
		(net "M_B_CPU1_SA_DQS_DN<3>")
	)
	(segment
		(start 79.86522 -263.26846)
		(end 78.210156 -263.95426)
		(width 0.18288)
		(layer "In4.Cu")
		(net "M_B_CPU1_SA_DQS_DN<3>")
	)
	(segment
		(start 72.110346 -270.05407)
		(end 71.934324 -270.05407)
		(width 0.18288)
		(layer "In4.Cu")
		(net "M_B_CPU1_SA_DQS_DN<3>")
	)
	(segment
		(start 50.872644 -284.442154)
		(end 50.600102 -284.714696)
		(width 0.18288)
		(layer "In4.Cu")
		(net "M_B_CPU1_SA_DQS_DN<3>")
	)
	(segment
		(start 47.223172 -284.27553)
		(end 46.964346 -284.016704)
		(width 0.18288)
		(layer "In4.Cu")
		(net "M_B_CPU1_SA_DQS_DN<3>")
	)
	(segment
		(start 64.63919 -277.176484)
		(end 64.295528 -277.5204)
		(width 0.18288)
		(layer "In4.Cu")
		(net "M_B_CPU1_SA_DQS_DN<3>")
	)
	(segment
		(start 82.893916 -263.32815)
		(end 82.834226 -263.26846)
		(width 0.088646)
		(layer "In4.Cu")
		(net "M_B_CPU1_SA_DQS_DN<3>")
	)
	(segment
		(start 51.33086 -284.532578)
		(end 51.240436 -284.442154)
		(width 0.18288)
		(layer "In4.Cu")
		(net "M_B_CPU1_SA_DQS_DN<3>")
	)
	(segment
		(start 72.886316 -269.102078)
		(end 72.498204 -269.49019)
		(width 0.18288)
		(layer "In4.Cu")
		(net "M_B_CPU1_SA_DQS_DN<3>")
	)
	(segment
		(start 70.59422 -271.570196)
		(end 70.206362 -271.958054)
		(width 0.18288)
		(layer "In4.Cu")
		(net "M_B_CPU1_SA_DQS_DN<3>")
	)
	(segment
		(start 72.498204 -269.49019)
		(end 72.498204 -269.666212)
		(width 0.18288)
		(layer "In4.Cu")
		(net "M_B_CPU1_SA_DQS_DN<3>")
	)
	(segment
		(start 64.295528 -277.5204)
		(end 63.360046 -278.145494)
		(width 0.18288)
		(layer "In4.Cu")
		(net "M_B_CPU1_SA_DQS_DN<3>")
	)
	(segment
		(start 78.210156 -263.95426)
		(end 77.822552 -264.342118)
		(width 0.18288)
		(layer "In4.Cu")
		(net "M_B_CPU1_SA_DQS_DN<3>")
	)
	(segment
		(start 52.009802 -284.470602)
		(end 51.4858 -284.687264)
		(width 0.18288)
		(layer "In4.Cu")
		(net "M_B_CPU1_SA_DQS_DN<3>")
	)
	(segment
		(start 83.329272 -263.147048)
		(end 83.14817 -263.32815)
		(width 0.088646)
		(layer "In4.Cu")
		(net "M_B_CPU1_SA_DQS_DN<3>")
	)
	(segment
		(start 70.59422 -271.394174)
		(end 70.59422 -271.570196)
		(width 0.18288)
		(layer "In4.Cu")
		(net "M_B_CPU1_SA_DQS_DN<3>")
	)
	(segment
		(start 56.38673 -281.26055)
		(end 55.822088 -281.825192)
		(width 0.18288)
		(layer "In4.Cu")
		(net "M_B_CPU1_SA_DQS_DN<3>")
	)
	(segment
		(start 76.306172 -265.858244)
		(end 75.918314 -266.246102)
		(width 0.18288)
		(layer "In4.Cu")
		(net "M_B_CPU1_SA_DQS_DN<3>")
	)
	(segment
		(start 74.7903 -267.198094)
		(end 74.402188 -267.586206)
		(width 0.18288)
		(layer "In4.Cu")
		(net "M_B_CPU1_SA_DQS_DN<3>")
	)
	(segment
		(start 58.198258 -281.26055)
		(end 56.38673 -281.26055)
		(width 0.18288)
		(layer "In4.Cu")
		(net "M_B_CPU1_SA_DQS_DN<3>")
	)
	(segment
		(start 75.918314 -266.246102)
		(end 75.742292 -266.246102)
		(width 0.18288)
		(layer "In4.Cu")
		(net "M_B_CPU1_SA_DQS_DN<3>")
	)
	(segment
		(start 68.438776 -273.72564)
		(end 65.758568 -274.834858)
		(width 0.18288)
		(layer "In4.Cu")
		(net "M_B_CPU1_SA_DQS_DN<3>")
	)
	(segment
		(start 83.14817 -263.32815)
		(end 82.893916 -263.32815)
		(width 0.088646)
		(layer "In4.Cu")
		(net "M_B_CPU1_SA_DQS_DN<3>")
	)
	(segment
		(start 74.01433 -268.150086)
		(end 73.838308 -268.150086)
		(width 0.18288)
		(layer "In4.Cu")
		(net "M_B_CPU1_SA_DQS_DN<3>")
	)
	(segment
		(start 77.646276 -264.342118)
		(end 77.258164 -264.73023)
		(width 0.18288)
		(layer "In4.Cu")
		(net "M_B_CPU1_SA_DQS_DN<3>")
	)
	(segment
		(start 73.838308 -268.150086)
		(end 73.450196 -268.538198)
		(width 0.18288)
		(layer "In4.Cu")
		(net "M_B_CPU1_SA_DQS_DN<3>")
	)
	(segment
		(start 91.512644 -262.988298)
		(end 91.473782 -263.010396)
		(width 0.088646)
		(layer "In4.Cu")
		(net "M_B_CPU1_SA_DQS_DN<3>")
	)
	(segment
		(start 51.240436 -284.442154)
		(end 50.872644 -284.442154)
		(width 0.18288)
		(layer "In4.Cu")
		(net "M_B_CPU1_SA_DQS_DN<3>")
	)
	(segment
		(start 65.758568 -274.834858)
		(end 65.615566 -274.992592)
		(width 0.18288)
		(layer "In4.Cu")
		(net "M_B_CPU1_SA_DQS_DN<3>")
	)
	(segment
		(start 73.062338 -269.102078)
		(end 72.886316 -269.102078)
		(width 0.18288)
		(layer "In4.Cu")
		(net "M_B_CPU1_SA_DQS_DN<3>")
	)
	(segment
		(start 73.450196 -268.538198)
		(end 73.450196 -268.71422)
		(width 0.18288)
		(layer "In4.Cu")
		(net "M_B_CPU1_SA_DQS_DN<3>")
	)
	(segment
		(start 47.946056 -284.09265)
		(end 47.763176 -284.27553)
		(width 0.18288)
		(layer "In4.Cu")
		(net "M_B_CPU1_SA_DQS_DN<3>")
	)
	(segment
		(start 71.546212 -270.618204)
		(end 71.158354 -271.006062)
		(width 0.18288)
		(layer "In4.Cu")
		(net "M_B_CPU1_SA_DQS_DN<3>")
	)
	(segment
		(start 74.402188 -267.586206)
		(end 74.402188 -267.762228)
		(width 0.18288)
		(layer "In4.Cu")
		(net "M_B_CPU1_SA_DQS_DN<3>")
	)
	(segment
		(start 75.35418 -266.634214)
		(end 75.35418 -266.810236)
		(width 0.18288)
		(layer "In4.Cu")
		(net "M_B_CPU1_SA_DQS_DN<3>")
	)
	(segment
		(start 91.045538 -263.05129)
		(end 90.7923 -263.197086)
		(width 0.088646)
		(layer "In4.Cu")
		(net "M_B_CPU1_SA_DQS_DN<3>")
	)
	(segment
		(start 61.852048 -278.770334)
		(end 60.1853 -280.437082)
		(width 0.18288)
		(layer "In4.Cu")
		(net "M_B_CPU1_SA_DQS_DN<3>")
	)
	(segment
		(start 77.258164 -264.73023)
		(end 77.258164 -264.906252)
		(width 0.18288)
		(layer "In4.Cu")
		(net "M_B_CPU1_SA_DQS_DN<3>")
	)
	(segment
		(start 55.822088 -281.825192)
		(end 55.460138 -282.36672)
		(width 0.18288)
		(layer "In4.Cu")
		(net "M_B_CPU1_SA_DQS_DN<3>")
	)
	(segment
		(start 71.158354 -271.006062)
		(end 70.982332 -271.006062)
		(width 0.18288)
		(layer "In4.Cu")
		(net "M_B_CPU1_SA_DQS_DN<3>")
	)
	(segment
		(start 75.742292 -266.246102)
		(end 75.35418 -266.634214)
		(width 0.18288)
		(layer "In4.Cu")
		(net "M_B_CPU1_SA_DQS_DN<3>")
	)
	(segment
		(start 76.694284 -265.29411)
		(end 76.306172 -265.682222)
		(width 0.18288)
		(layer "In4.Cu")
		(net "M_B_CPU1_SA_DQS_DN<3>")
	)
	(segment
		(start 91.319096 -263.05129)
		(end 91.045538 -263.05129)
		(width 0.088646)
		(layer "In4.Cu")
		(net "M_B_CPU1_SA_DQS_DN<3>")
	)
	(segment
		(start 76.306172 -265.682222)
		(end 76.306172 -265.858244)
		(width 0.18288)
		(layer "In4.Cu")
		(net "M_B_CPU1_SA_DQS_DN<3>")
	)
	(segment
		(start 82.783934 -263.26846)
		(end 79.86522 -263.26846)
		(width 0.18288)
		(layer "In4.Cu")
		(net "M_B_CPU1_SA_DQS_DN<3>")
	)
	(segment
		(start 77.258164 -264.906252)
		(end 76.870306 -265.29411)
		(width 0.18288)
		(layer "In4.Cu")
		(net "M_B_CPU1_SA_DQS_DN<3>")
	)
	(segment
		(start 76.870306 -265.29411)
		(end 76.694284 -265.29411)
		(width 0.18288)
		(layer "In4.Cu")
		(net "M_B_CPU1_SA_DQS_DN<3>")
	)
	(segment
		(start 70.03034 -271.958054)
		(end 69.642228 -272.346166)
		(width 0.18288)
		(layer "In4.Cu")
		(net "M_B_CPU1_SA_DQS_DN<3>")
	)
	(segment
		(start 70.206362 -271.958054)
		(end 70.03034 -271.958054)
		(width 0.18288)
		(layer "In4.Cu")
		(net "M_B_CPU1_SA_DQS_DN<3>")
	)
	(segment
		(start 63.360046 -278.145494)
		(end 61.852048 -278.770334)
		(width 0.18288)
		(layer "In4.Cu")
		(net "M_B_CPU1_SA_DQS_DN<3>")
	)
	(segment
		(start 52.59451 -284.470602)
		(end 52.009802 -284.470602)
		(width 0.18288)
		(layer "In4.Cu")
		(net "M_B_CPU1_SA_DQS_DN<3>")
	)
	(segment
		(start 54.74208 -283.58084)
		(end 52.59451 -284.470602)
		(width 0.18288)
		(layer "In4.Cu")
		(net "M_B_CPU1_SA_DQS_DN<3>")
	)
	(segment
		(start 47.763176 -284.27553)
		(end 47.223172 -284.27553)
		(width 0.18288)
		(layer "In4.Cu")
		(net "M_B_CPU1_SA_DQS_DN<3>")
	)
	(segment
		(start 90.7923 -263.197086)
		(end 90.792046 -263.196832)
		(width 0.088646)
		(layer "In4.Cu")
		(net "M_B_CPU1_SA_DQS_DN<3>")
	)
	(segment
		(start 71.934324 -270.05407)
		(end 71.546212 -270.442182)
		(width 0.18288)
		(layer "In4.Cu")
		(net "M_B_CPU1_SA_DQS_DN<3>")
	)
	(segment
		(start 83.651344 -263.147048)
		(end 83.329272 -263.147048)
		(width 0.088646)
		(layer "In4.Cu")
		(net "M_B_CPU1_SA_DQS_DN<3>")
	)
	(segment
		(start 49.692814 -284.09265)
		(end 47.946056 -284.09265)
		(width 0.18288)
		(layer "In4.Cu")
		(net "M_B_CPU1_SA_DQS_DN<3>")
	)
	(segment
		(start 91.544394 -262.872474)
		(end 91.512644 -262.988298)
		(width 0.088646)
		(layer "In4.Cu")
		(net "M_B_CPU1_SA_DQS_DN<3>")
	)
	(segment
		(start 69.642228 -272.346166)
		(end 69.642228 -272.522188)
		(width 0.18288)
		(layer "In4.Cu")
		(net "M_B_CPU1_SA_DQS_DN<3>")
	)
	(segment
		(start 72.498204 -269.666212)
		(end 72.110346 -270.05407)
		(width 0.18288)
		(layer "In4.Cu")
		(net "M_B_CPU1_SA_DQS_DN<3>")
	)
	(arc
		(start 83.838796 -263.197594)
		(mid 83.748407 -263.159947)
		(end 83.651344 -263.147048)
		(width 0.088646)
		(layer "In4.Cu")
		(net "M_B_CPU1_SA_DQS_DN<3>")
	)
	(arc
		(start 88.912192 -263.196832)
		(mid 88.724994 -263.246975)
		(end 88.537796 -263.196832)
		(width 0.088646)
		(layer "In4.Cu")
		(net "M_B_CPU1_SA_DQS_DN<3>")
	)
	(arc
		(start 90.41765 -263.196832)
		(mid 90.140837 -263.120996)
		(end 89.862406 -263.190736)
		(width 0.088646)
		(layer "In4.Cu")
		(net "M_B_CPU1_SA_DQS_DN<3>")
	)
	(arc
		(start 86.092792 -263.196832)
		(mid 85.905594 -263.246975)
		(end 85.718396 -263.196832)
		(width 0.088646)
		(layer "In4.Cu")
		(net "M_B_CPU1_SA_DQS_DN<3>")
	)
	(arc
		(start 89.477596 -263.196832)
		(mid 89.194894 -263.12109)
		(end 88.912192 -263.196832)
		(width 0.088646)
		(layer "In4.Cu")
		(net "M_B_CPU1_SA_DQS_DN<3>")
	)
	(arc
		(start 86.658196 -263.196832)
		(mid 86.375494 -263.12109)
		(end 86.092792 -263.196832)
		(width 0.088646)
		(layer "In4.Cu")
		(net "M_B_CPU1_SA_DQS_DN<3>")
	)
	(arc
		(start 85.718396 -263.196832)
		(mid 85.435694 -263.12109)
		(end 85.152992 -263.196832)
		(width 0.088646)
		(layer "In4.Cu")
		(net "M_B_CPU1_SA_DQS_DN<3>")
	)
	(arc
		(start 87.597996 -263.196832)
		(mid 87.315294 -263.12109)
		(end 87.032592 -263.196832)
		(width 0.088646)
		(layer "In4.Cu")
		(net "M_B_CPU1_SA_DQS_DN<3>")
	)
	(arc
		(start 87.972392 -263.196832)
		(mid 87.785194 -263.246975)
		(end 87.597996 -263.196832)
		(width 0.088646)
		(layer "In4.Cu")
		(net "M_B_CPU1_SA_DQS_DN<3>")
	)
	(arc
		(start 84.2137 -263.19734)
		(mid 84.026277 -263.247669)
		(end 83.838796 -263.197594)
		(width 0.088646)
		(layer "In4.Cu")
		(net "M_B_CPU1_SA_DQS_DN<3>")
	)
	(arc
		(start 84.778596 -263.196832)
		(mid 84.496089 -263.121471)
		(end 84.2137 -263.19734)
		(width 0.088646)
		(layer "In4.Cu")
		(net "M_B_CPU1_SA_DQS_DN<3>")
	)
	(arc
		(start 87.032592 -263.196832)
		(mid 86.845394 -263.246975)
		(end 86.658196 -263.196832)
		(width 0.088646)
		(layer "In4.Cu")
		(net "M_B_CPU1_SA_DQS_DN<3>")
	)
	(arc
		(start 88.537796 -263.196832)
		(mid 88.255094 -263.12109)
		(end 87.972392 -263.196832)
		(width 0.088646)
		(layer "In4.Cu")
		(net "M_B_CPU1_SA_DQS_DN<3>")
	)
	(arc
		(start 89.851992 -263.196832)
		(mid 89.664794 -263.246975)
		(end 89.477596 -263.196832)
		(width 0.088646)
		(layer "In4.Cu")
		(net "M_B_CPU1_SA_DQS_DN<3>")
	)
	(arc
		(start 91.473782 -263.010396)
		(mid 91.399097 -263.040901)
		(end 91.319096 -263.05129)
		(width 0.088646)
		(layer "In4.Cu")
		(net "M_B_CPU1_SA_DQS_DN<3>")
	)
	(arc
		(start 90.792046 -263.196832)
		(mid 90.604848 -263.246975)
		(end 90.41765 -263.196832)
		(width 0.088646)
		(layer "In4.Cu")
		(net "M_B_CPU1_SA_DQS_DN<3>")
	)
	(arc
		(start 85.152992 -263.196832)
		(mid 84.965794 -263.246975)
		(end 84.778596 -263.196832)
		(width 0.088646)
		(layer "In4.Cu")
		(net "M_B_CPU1_SA_DQS_DN<3>")
	)
	(segment
		(start 45.051726 -293.62781)
		(end 44.645072 -293.62781)
		(width 0.20066)
		(layer "F.Cu")
		(net "M_B_CPU1_SA_DQS_DN<2>")
	)
	(segment
		(start 40.275256 -294.053006)
		(end 39.63924 -293.62781)
		(width 0.20066)
		(layer "F.Cu")
		(net "M_B_CPU1_SA_DQS_DN<2>")
	)
	(segment
		(start 41.292272 -293.780972)
		(end 41.29151 -293.780972)
		(width 0.101854)
		(layer "F.Cu")
		(net "M_B_CPU1_SA_DQS_DN<2>")
	)
	(segment
		(start 44.219876 -294.053006)
		(end 44.033186 -294.053006)
		(width 0.20066)
		(layer "F.Cu")
		(net "M_B_CPU1_SA_DQS_DN<2>")
	)
	(segment
		(start 45.312838 -293.366698)
		(end 45.051726 -293.62781)
		(width 0.20066)
		(layer "F.Cu")
		(net "M_B_CPU1_SA_DQS_DN<2>")
	)
	(segment
		(start 41.29151 -293.780972)
		(end 41.087294 -293.780972)
		(width 0.20066)
		(layer "F.Cu")
		(net "M_B_CPU1_SA_DQS_DN<2>")
	)
	(segment
		(start 44.645072 -293.62781)
		(end 44.219876 -294.053006)
		(width 0.20066)
		(layer "F.Cu")
		(net "M_B_CPU1_SA_DQS_DN<2>")
	)
	(segment
		(start 46.964346 -293.366698)
		(end 45.859446 -293.366698)
		(width 0.20066)
		(layer "F.Cu")
		(net "M_B_CPU1_SA_DQS_DN<2>")
	)
	(segment
		(start 39.63924 -293.62781)
		(end 39.125398 -293.62781)
		(width 0.20066)
		(layer "F.Cu")
		(net "M_B_CPU1_SA_DQS_DN<2>")
	)
	(segment
		(start 40.81526 -294.053006)
		(end 40.275256 -294.053006)
		(width 0.20066)
		(layer "F.Cu")
		(net "M_B_CPU1_SA_DQS_DN<2>")
	)
	(segment
		(start 44.033186 -294.053006)
		(end 43.77182 -293.79164)
		(width 0.20066)
		(layer "F.Cu")
		(net "M_B_CPU1_SA_DQS_DN<2>")
	)
	(segment
		(start 41.30294 -293.79164)
		(end 41.292272 -293.780972)
		(width 0.101854)
		(layer "F.Cu")
		(net "M_B_CPU1_SA_DQS_DN<2>")
	)
	(segment
		(start 38.864286 -293.366698)
		(end 38.315646 -293.366698)
		(width 0.20066)
		(layer "F.Cu")
		(net "M_B_CPU1_SA_DQS_DN<2>")
	)
	(segment
		(start 39.125398 -293.62781)
		(end 38.864286 -293.366698)
		(width 0.20066)
		(layer "F.Cu")
		(net "M_B_CPU1_SA_DQS_DN<2>")
	)
	(segment
		(start 45.859446 -293.366698)
		(end 45.312838 -293.366698)
		(width 0.20066)
		(layer "F.Cu")
		(net "M_B_CPU1_SA_DQS_DN<2>")
	)
	(segment
		(start 41.087294 -293.780972)
		(end 40.81526 -294.053006)
		(width 0.20066)
		(layer "F.Cu")
		(net "M_B_CPU1_SA_DQS_DN<2>")
	)
	(segment
		(start 43.616626 -293.79164)
		(end 41.30294 -293.79164)
		(width 0.1016)
		(layer "F.Cu")
		(net "M_B_CPU1_SA_DQS_DN<2>")
	)
	(segment
		(start 88.255094 -264.778236)
		(end 88.255094 -265.314176)
		(width 0.20066)
		(layer "F.Cu")
		(net "M_B_CPU1_SA_DQS_DN<2>")
	)
	(segment
		(start 43.77182 -293.79164)
		(end 43.616626 -293.79164)
		(width 0.20066)
		(layer "F.Cu")
		(net "M_B_CPU1_SA_DQS_DN<2>")
	)
	(segment
		(start 80.53705 -268.830298)
		(end 80.28686 -268.93393)
		(width 0.18288)
		(layer "In2.Cu")
		(net "M_B_CPU1_SA_DQS_DN<2>")
	)
	(segment
		(start 69.317616 -281.243024)
		(end 68.929758 -281.630882)
		(width 0.18288)
		(layer "In2.Cu")
		(net "M_B_CPU1_SA_DQS_DN<2>")
	)
	(segment
		(start 64.118998 -285.077154)
		(end 64.118998 -285.092902)
		(width 0.16002)
		(layer "In2.Cu")
		(net "M_B_CPU1_SA_DQS_DN<2>")
	)
	(segment
		(start 78.790546 -270.430244)
		(end 78.614524 -270.430244)
		(width 0.18288)
		(layer "In2.Cu")
		(net "M_B_CPU1_SA_DQS_DN<2>")
	)
	(segment
		(start 77.838554 -271.382236)
		(end 77.662532 -271.382236)
		(width 0.18288)
		(layer "In2.Cu")
		(net "M_B_CPU1_SA_DQS_DN<2>")
	)
	(segment
		(start 76.322428 -272.898362)
		(end 75.93457 -273.28622)
		(width 0.18288)
		(layer "In2.Cu")
		(net "M_B_CPU1_SA_DQS_DN<2>")
	)
	(segment
		(start 64.118998 -285.092902)
		(end 63.918846 -285.293054)
		(width 0.16002)
		(layer "In2.Cu")
		(net "M_B_CPU1_SA_DQS_DN<2>")
	)
	(segment
		(start 70.419976 -280.140664)
		(end 69.882004 -280.678636)
		(width 0.18288)
		(layer "In2.Cu")
		(net "M_B_CPU1_SA_DQS_DN<2>")
	)
	(segment
		(start 76.71054 -272.334228)
		(end 76.322428 -272.72234)
		(width 0.18288)
		(layer "In2.Cu")
		(net "M_B_CPU1_SA_DQS_DN<2>")
	)
	(segment
		(start 61.900054 -286.742886)
		(end 61.87186 -286.77108)
		(width 0.16002)
		(layer "In2.Cu")
		(net "M_B_CPU1_SA_DQS_DN<2>")
	)
	(segment
		(start 61.627766 -287.015174)
		(end 61.31433 -287.32861)
		(width 0.18288)
		(layer "In2.Cu")
		(net "M_B_CPU1_SA_DQS_DN<2>")
	)
	(segment
		(start 68.365624 -282.018994)
		(end 68.365624 -282.195016)
		(width 0.18288)
		(layer "In2.Cu")
		(net "M_B_CPU1_SA_DQS_DN<2>")
	)
	(segment
		(start 57.810654 -291.61105)
		(end 56.85663 -291.61105)
		(width 0.18288)
		(layer "In2.Cu")
		(net "M_B_CPU1_SA_DQS_DN<2>")
	)
	(segment
		(start 66.76263 -283.79801)
		(end 66.395092 -283.79801)
		(width 0.18288)
		(layer "In2.Cu")
		(net "M_B_CPU1_SA_DQS_DN<2>")
	)
	(segment
		(start 88.215724 -265.314176)
		(end 88.03386 -265.49604)
		(width 0.088646)
		(layer "In2.Cu")
		(net "M_B_CPU1_SA_DQS_DN<2>")
	)
	(segment
		(start 59.87796 -287.801558)
		(end 59.862212 -287.801558)
		(width 0.16002)
		(layer "In2.Cu")
		(net "M_B_CPU1_SA_DQS_DN<2>")
	)
	(segment
		(start 73.466452 -275.578316)
		(end 73.466452 -275.754338)
		(width 0.18288)
		(layer "In2.Cu")
		(net "M_B_CPU1_SA_DQS_DN<2>")
	)
	(segment
		(start 83.552538 -265.899138)
		(end 82.546952 -266.904724)
		(width 0.088646)
		(layer "In2.Cu")
		(net "M_B_CPU1_SA_DQS_DN<2>")
	)
	(segment
		(start 68.753736 -281.630882)
		(end 68.365624 -282.018994)
		(width 0.18288)
		(layer "In2.Cu")
		(net "M_B_CPU1_SA_DQS_DN<2>")
	)
	(segment
		(start 61.65596 -286.98698)
		(end 61.627766 -287.015174)
		(width 0.16002)
		(layer "In2.Cu")
		(net "M_B_CPU1_SA_DQS_DN<2>")
	)
	(segment
		(start 54.173374 -294.576754)
		(end 54.157118 -294.576754)
		(width 0.16002)
		(layer "In2.Cu")
		(net "M_B_CPU1_SA_DQS_DN<2>")
	)
	(segment
		(start 58.116724 -291.30498)
		(end 57.810654 -291.61105)
		(width 0.18288)
		(layer "In2.Cu")
		(net "M_B_CPU1_SA_DQS_DN<2>")
	)
	(segment
		(start 63.127382 -286.06877)
		(end 62.57417 -286.06877)
		(width 0.18288)
		(layer "In2.Cu")
		(net "M_B_CPU1_SA_DQS_DN<2>")
	)
	(segment
		(start 59.05754 -288.915602)
		(end 59.05754 -290.120324)
		(width 0.18288)
		(layer "In2.Cu")
		(net "M_B_CPU1_SA_DQS_DN<2>")
	)
	(segment
		(start 80.28686 -268.93393)
		(end 79.742538 -269.478252)
		(width 0.18288)
		(layer "In2.Cu")
		(net "M_B_CPU1_SA_DQS_DN<2>")
	)
	(segment
		(start 64.147192 -285.04896)
		(end 64.118998 -285.077154)
		(width 0.16002)
		(layer "In2.Cu")
		(net "M_B_CPU1_SA_DQS_DN<2>")
	)
	(segment
		(start 84.683346 -265.63828)
		(end 84.6836 -265.639042)
		(width 0.088646)
		(layer "In2.Cu")
		(net "M_B_CPU1_SA_DQS_DN<2>")
	)
	(segment
		(start 70.419976 -278.800814)
		(end 70.419976 -280.140664)
		(width 0.18288)
		(layer "In2.Cu")
		(net "M_B_CPU1_SA_DQS_DN<2>")
	)
	(segment
		(start 82.462878 -266.904724)
		(end 80.53705 -268.830298)
		(width 0.18288)
		(layer "In2.Cu")
		(net "M_B_CPU1_SA_DQS_DN<2>")
	)
	(segment
		(start 54.128924 -294.604948)
		(end 54.013862 -294.72001)
		(width 0.18288)
		(layer "In2.Cu")
		(net "M_B_CPU1_SA_DQS_DN<2>")
	)
	(segment
		(start 66.395092 -283.79801)
		(end 66.000122 -284.19298)
		(width 0.18288)
		(layer "In2.Cu")
		(net "M_B_CPU1_SA_DQS_DN<2>")
	)
	(segment
		(start 78.226412 -270.994378)
		(end 77.838554 -271.382236)
		(width 0.18288)
		(layer "In2.Cu")
		(net "M_B_CPU1_SA_DQS_DN<2>")
	)
	(segment
		(start 58.357262 -291.05733)
		(end 58.357262 -291.080698)
		(width 0.16002)
		(layer "In2.Cu")
		(net "M_B_CPU1_SA_DQS_DN<2>")
	)
	(segment
		(start 62.57417 -286.06877)
		(end 61.900054 -286.742886)
		(width 0.18288)
		(layer "In2.Cu")
		(net "M_B_CPU1_SA_DQS_DN<2>")
	)
	(segment
		(start 52.40528 -294.33266)
		(end 52.130452 -294.057832)
		(width 0.18288)
		(layer "In2.Cu")
		(net "M_B_CPU1_SA_DQS_DN<2>")
	)
	(segment
		(start 74.982578 -274.238212)
		(end 74.806556 -274.238212)
		(width 0.18288)
		(layer "In2.Cu")
		(net "M_B_CPU1_SA_DQS_DN<2>")
	)
	(segment
		(start 49.114202 -293.666926)
		(end 49.114202 -293.65067)
		(width 0.16002)
		(layer "In2.Cu")
		(net "M_B_CPU1_SA_DQS_DN<2>")
	)
	(segment
		(start 63.874904 -285.321248)
		(end 63.127382 -286.06877)
		(width 0.18288)
		(layer "In2.Cu")
		(net "M_B_CPU1_SA_DQS_DN<2>")
	)
	(segment
		(start 49.313846 -293.86657)
		(end 49.114202 -293.666926)
		(width 0.16002)
		(layer "In2.Cu")
		(net "M_B_CPU1_SA_DQS_DN<2>")
	)
	(segment
		(start 72.902572 -276.142196)
		(end 72.51446 -276.530308)
		(width 0.18288)
		(layer "In2.Cu")
		(net "M_B_CPU1_SA_DQS_DN<2>")
	)
	(segment
		(start 60.33516 -287.32861)
		(end 60.106306 -287.557464)
		(width 0.18288)
		(layer "In2.Cu")
		(net "M_B_CPU1_SA_DQS_DN<2>")
	)
	(segment
		(start 58.357262 -291.080698)
		(end 58.161174 -291.276786)
		(width 0.16002)
		(layer "In2.Cu")
		(net "M_B_CPU1_SA_DQS_DN<2>")
	)
	(segment
		(start 59.276742 -288.387028)
		(end 59.05754 -288.915602)
		(width 0.18288)
		(layer "In2.Cu")
		(net "M_B_CPU1_SA_DQS_DN<2>")
	)
	(segment
		(start 69.317616 -281.067002)
		(end 69.317616 -281.243024)
		(width 0.18288)
		(layer "In2.Cu")
		(net "M_B_CPU1_SA_DQS_DN<2>")
	)
	(segment
		(start 79.178404 -270.042386)
		(end 78.790546 -270.430244)
		(width 0.18288)
		(layer "In2.Cu")
		(net "M_B_CPU1_SA_DQS_DN<2>")
	)
	(segment
		(start 61.87186 -286.787336)
		(end 61.672216 -286.98698)
		(width 0.16002)
		(layer "In2.Cu")
		(net "M_B_CPU1_SA_DQS_DN<2>")
	)
	(segment
		(start 65.772284 -284.437074)
		(end 65.756028 -284.437074)
		(width 0.16002)
		(layer "In2.Cu")
		(net "M_B_CPU1_SA_DQS_DN<2>")
	)
	(segment
		(start 79.178404 -269.866364)
		(end 79.178404 -270.042386)
		(width 0.18288)
		(layer "In2.Cu")
		(net "M_B_CPU1_SA_DQS_DN<2>")
	)
	(segment
		(start 51.358038 -293.79164)
		(end 50.86096 -293.79164)
		(width 0.18288)
		(layer "In2.Cu")
		(net "M_B_CPU1_SA_DQS_DN<2>")
	)
	(segment
		(start 56.330088 -292.15334)
		(end 56.31434 -292.15334)
		(width 0.16002)
		(layer "In2.Cu")
		(net "M_B_CPU1_SA_DQS_DN<2>")
	)
	(segment
		(start 77.27442 -271.94637)
		(end 76.886562 -272.334228)
		(width 0.18288)
		(layer "In2.Cu")
		(net "M_B_CPU1_SA_DQS_DN<2>")
	)
	(segment
		(start 49.358296 -293.894764)
		(end 49.330102 -293.86657)
		(width 0.16002)
		(layer "In2.Cu")
		(net "M_B_CPU1_SA_DQS_DN<2>")
	)
	(segment
		(start 68.365624 -282.195016)
		(end 66.76263 -283.79801)
		(width 0.18288)
		(layer "In2.Cu")
		(net "M_B_CPU1_SA_DQS_DN<2>")
	)
	(segment
		(start 56.558434 -291.909246)
		(end 56.53024 -291.93744)
		(width 0.16002)
		(layer "In2.Cu")
		(net "M_B_CPU1_SA_DQS_DN<2>")
	)
	(segment
		(start 64.53632 -284.659832)
		(end 64.147192 -285.04896)
		(width 0.18288)
		(layer "In2.Cu")
		(net "M_B_CPU1_SA_DQS_DN<2>")
	)
	(segment
		(start 75.370436 -273.850354)
		(end 74.982578 -274.238212)
		(width 0.18288)
		(layer "In2.Cu")
		(net "M_B_CPU1_SA_DQS_DN<2>")
	)
	(segment
		(start 56.31434 -292.15334)
		(end 56.286146 -292.181534)
		(width 0.16002)
		(layer "In2.Cu")
		(net "M_B_CPU1_SA_DQS_DN<2>")
	)
	(segment
		(start 59.05754 -290.120324)
		(end 58.883804 -290.5379)
		(width 0.18288)
		(layer "In2.Cu")
		(net "M_B_CPU1_SA_DQS_DN<2>")
	)
	(segment
		(start 48.259238 -293.37889)
		(end 47.60849 -293.648384)
		(width 0.18288)
		(layer "In2.Cu")
		(net "M_B_CPU1_SA_DQS_DN<2>")
	)
	(segment
		(start 48.842422 -293.37889)
		(end 48.259238 -293.37889)
		(width 0.18288)
		(layer "In2.Cu")
		(net "M_B_CPU1_SA_DQS_DN<2>")
	)
	(segment
		(start 47.60849 -293.648384)
		(end 47.246032 -293.648384)
		(width 0.18288)
		(layer "In2.Cu")
		(net "M_B_CPU1_SA_DQS_DN<2>")
	)
	(segment
		(start 54.373018 -294.37711)
		(end 54.173374 -294.576754)
		(width 0.16002)
		(layer "In2.Cu")
		(net "M_B_CPU1_SA_DQS_DN<2>")
	)
	(segment
		(start 56.85663 -291.61105)
		(end 56.558434 -291.909246)
		(width 0.18288)
		(layer "In2.Cu")
		(net "M_B_CPU1_SA_DQS_DN<2>")
	)
	(segment
		(start 49.527968 -294.064436)
		(end 49.358296 -293.894764)
		(width 0.18288)
		(layer "In2.Cu")
		(net "M_B_CPU1_SA_DQS_DN<2>")
	)
	(segment
		(start 61.31433 -287.32861)
		(end 60.33516 -287.32861)
		(width 0.18288)
		(layer "In2.Cu")
		(net "M_B_CPU1_SA_DQS_DN<2>")
	)
	(segment
		(start 73.854564 -275.190204)
		(end 73.466452 -275.578316)
		(width 0.18288)
		(layer "In2.Cu")
		(net "M_B_CPU1_SA_DQS_DN<2>")
	)
	(segment
		(start 65.53327 -284.659832)
		(end 64.53632 -284.659832)
		(width 0.18288)
		(layer "In2.Cu")
		(net "M_B_CPU1_SA_DQS_DN<2>")
	)
	(segment
		(start 54.761638 -293.972234)
		(end 54.401212 -294.33266)
		(width 0.18288)
		(layer "In2.Cu")
		(net "M_B_CPU1_SA_DQS_DN<2>")
	)
	(segment
		(start 54.013862 -294.72001)
		(end 52.79263 -294.72001)
		(width 0.18288)
		(layer "In2.Cu")
		(net "M_B_CPU1_SA_DQS_DN<2>")
	)
	(segment
		(start 74.030586 -275.190204)
		(end 73.854564 -275.190204)
		(width 0.18288)
		(layer "In2.Cu")
		(net "M_B_CPU1_SA_DQS_DN<2>")
	)
	(segment
		(start 88.255094 -265.314176)
		(end 88.215724 -265.314176)
		(width 0.088646)
		(layer "In2.Cu")
		(net "M_B_CPU1_SA_DQS_DN<2>")
	)
	(segment
		(start 74.418444 -274.802346)
		(end 74.030586 -275.190204)
		(width 0.18288)
		(layer "In2.Cu")
		(net "M_B_CPU1_SA_DQS_DN<2>")
	)
	(segment
		(start 63.903098 -285.293054)
		(end 63.874904 -285.321248)
		(width 0.16002)
		(layer "In2.Cu")
		(net "M_B_CPU1_SA_DQS_DN<2>")
	)
	(segment
		(start 69.882004 -280.678636)
		(end 69.705982 -280.678636)
		(width 0.18288)
		(layer "In2.Cu")
		(net "M_B_CPU1_SA_DQS_DN<2>")
	)
	(segment
		(start 65.971928 -284.23743)
		(end 65.772284 -284.437074)
		(width 0.16002)
		(layer "In2.Cu")
		(net "M_B_CPU1_SA_DQS_DN<2>")
	)
	(segment
		(start 65.727834 -284.465268)
		(end 65.53327 -284.659832)
		(width 0.18288)
		(layer "In2.Cu")
		(net "M_B_CPU1_SA_DQS_DN<2>")
	)
	(segment
		(start 56.53024 -291.953188)
		(end 56.330088 -292.15334)
		(width 0.16002)
		(layer "In2.Cu")
		(net "M_B_CPU1_SA_DQS_DN<2>")
	)
	(segment
		(start 58.364374 -291.05733)
		(end 58.357262 -291.05733)
		(width 0.18288)
		(layer "In2.Cu")
		(net "M_B_CPU1_SA_DQS_DN<2>")
	)
	(segment
		(start 79.742538 -269.478252)
		(end 79.566516 -269.478252)
		(width 0.18288)
		(layer "In2.Cu")
		(net "M_B_CPU1_SA_DQS_DN<2>")
	)
	(segment
		(start 56.286146 -292.181534)
		(end 54.761638 -293.706042)
		(width 0.18288)
		(layer "In2.Cu")
		(net "M_B_CPU1_SA_DQS_DN<2>")
	)
	(segment
		(start 63.918846 -285.293054)
		(end 63.903098 -285.293054)
		(width 0.16002)
		(layer "In2.Cu")
		(net "M_B_CPU1_SA_DQS_DN<2>")
	)
	(segment
		(start 58.883804 -290.5379)
		(end 58.364374 -291.05733)
		(width 0.18288)
		(layer "In2.Cu")
		(net "M_B_CPU1_SA_DQS_DN<2>")
	)
	(segment
		(start 72.126602 -277.094188)
		(end 71.95058 -277.094188)
		(width 0.18288)
		(layer "In2.Cu")
		(net "M_B_CPU1_SA_DQS_DN<2>")
	)
	(segment
		(start 61.672216 -286.98698)
		(end 61.65596 -286.98698)
		(width 0.16002)
		(layer "In2.Cu")
		(net "M_B_CPU1_SA_DQS_DN<2>")
	)
	(segment
		(start 61.87186 -286.77108)
		(end 61.87186 -286.787336)
		(width 0.16002)
		(layer "In2.Cu")
		(net "M_B_CPU1_SA_DQS_DN<2>")
	)
	(segment
		(start 78.614524 -270.430244)
		(end 78.226412 -270.818356)
		(width 0.18288)
		(layer "In2.Cu")
		(net "M_B_CPU1_SA_DQS_DN<2>")
	)
	(segment
		(start 75.370436 -273.674332)
		(end 75.370436 -273.850354)
		(width 0.18288)
		(layer "In2.Cu")
		(net "M_B_CPU1_SA_DQS_DN<2>")
	)
	(segment
		(start 73.078594 -276.142196)
		(end 72.902572 -276.142196)
		(width 0.18288)
		(layer "In2.Cu")
		(net "M_B_CPU1_SA_DQS_DN<2>")
	)
	(segment
		(start 59.834018 -287.829752)
		(end 59.276742 -288.387028)
		(width 0.18288)
		(layer "In2.Cu")
		(net "M_B_CPU1_SA_DQS_DN<2>")
	)
	(segment
		(start 68.929758 -281.630882)
		(end 68.753736 -281.630882)
		(width 0.18288)
		(layer "In2.Cu")
		(net "M_B_CPU1_SA_DQS_DN<2>")
	)
	(segment
		(start 54.373018 -294.360854)
		(end 54.373018 -294.37711)
		(width 0.16002)
		(layer "In2.Cu")
		(net "M_B_CPU1_SA_DQS_DN<2>")
	)
	(segment
		(start 56.53024 -291.93744)
		(end 56.53024 -291.953188)
		(width 0.16002)
		(layer "In2.Cu")
		(net "M_B_CPU1_SA_DQS_DN<2>")
	)
	(segment
		(start 52.433474 -294.37711)
		(end 52.433474 -294.360854)
		(width 0.16002)
		(layer "In2.Cu")
		(net "M_B_CPU1_SA_DQS_DN<2>")
	)
	(segment
		(start 54.401212 -294.33266)
		(end 54.373018 -294.360854)
		(width 0.16002)
		(layer "In2.Cu")
		(net "M_B_CPU1_SA_DQS_DN<2>")
	)
	(segment
		(start 52.633118 -294.576754)
		(end 52.433474 -294.37711)
		(width 0.16002)
		(layer "In2.Cu")
		(net "M_B_CPU1_SA_DQS_DN<2>")
	)
	(segment
		(start 60.106306 -287.557464)
		(end 60.078112 -287.585658)
		(width 0.16002)
		(layer "In2.Cu")
		(net "M_B_CPU1_SA_DQS_DN<2>")
	)
	(segment
		(start 50.86096 -293.79164)
		(end 50.588164 -294.064436)
		(width 0.18288)
		(layer "In2.Cu")
		(net "M_B_CPU1_SA_DQS_DN<2>")
	)
	(segment
		(start 78.226412 -270.818356)
		(end 78.226412 -270.994378)
		(width 0.18288)
		(layer "In2.Cu")
		(net "M_B_CPU1_SA_DQS_DN<2>")
	)
	(segment
		(start 60.078112 -287.585658)
		(end 60.078112 -287.601406)
		(width 0.16002)
		(layer "In2.Cu")
		(net "M_B_CPU1_SA_DQS_DN<2>")
	)
	(segment
		(start 65.756028 -284.437074)
		(end 65.727834 -284.465268)
		(width 0.16002)
		(layer "In2.Cu")
		(net "M_B_CPU1_SA_DQS_DN<2>")
	)
	(segment
		(start 52.79263 -294.72001)
		(end 52.677568 -294.604948)
		(width 0.18288)
		(layer "In2.Cu")
		(net "M_B_CPU1_SA_DQS_DN<2>")
	)
	(segment
		(start 52.649374 -294.576754)
		(end 52.633118 -294.576754)
		(width 0.16002)
		(layer "In2.Cu")
		(net "M_B_CPU1_SA_DQS_DN<2>")
	)
	(segment
		(start 54.157118 -294.576754)
		(end 54.128924 -294.604948)
		(width 0.16002)
		(layer "In2.Cu")
		(net "M_B_CPU1_SA_DQS_DN<2>")
	)
	(segment
		(start 54.761638 -293.706042)
		(end 54.761638 -293.972234)
		(width 0.18288)
		(layer "In2.Cu")
		(net "M_B_CPU1_SA_DQS_DN<2>")
	)
	(segment
		(start 83.91652 -265.690858)
		(end 83.67268 -265.812524)
		(width 0.088646)
		(layer "In2.Cu")
		(net "M_B_CPU1_SA_DQS_DN<2>")
	)
	(segment
		(start 74.806556 -274.238212)
		(end 74.418444 -274.626324)
		(width 0.18288)
		(layer "In2.Cu")
		(net "M_B_CPU1_SA_DQS_DN<2>")
	)
	(segment
		(start 49.086008 -293.622476)
		(end 48.842422 -293.37889)
		(width 0.18288)
		(layer "In2.Cu")
		(net "M_B_CPU1_SA_DQS_DN<2>")
	)
	(segment
		(start 52.677568 -294.604948)
		(end 52.649374 -294.576754)
		(width 0.16002)
		(layer "In2.Cu")
		(net "M_B_CPU1_SA_DQS_DN<2>")
	)
	(segment
		(start 73.466452 -275.754338)
		(end 73.078594 -276.142196)
		(width 0.18288)
		(layer "In2.Cu")
		(net "M_B_CPU1_SA_DQS_DN<2>")
	)
	(segment
		(start 52.433474 -294.360854)
		(end 52.40528 -294.33266)
		(width 0.16002)
		(layer "In2.Cu")
		(net "M_B_CPU1_SA_DQS_DN<2>")
	)
	(segment
		(start 51.62423 -294.057832)
		(end 51.358038 -293.79164)
		(width 0.18288)
		(layer "In2.Cu")
		(net "M_B_CPU1_SA_DQS_DN<2>")
	)
	(segment
		(start 59.862212 -287.801558)
		(end 59.834018 -287.829752)
		(width 0.16002)
		(layer "In2.Cu")
		(net "M_B_CPU1_SA_DQS_DN<2>")
	)
	(segment
		(start 65.971928 -284.221174)
		(end 65.971928 -284.23743)
		(width 0.16002)
		(layer "In2.Cu")
		(net "M_B_CPU1_SA_DQS_DN<2>")
	)
	(segment
		(start 47.246032 -293.648384)
		(end 46.964346 -293.366698)
		(width 0.18288)
		(layer "In2.Cu")
		(net "M_B_CPU1_SA_DQS_DN<2>")
	)
	(segment
		(start 82.546952 -266.904724)
		(end 82.462878 -266.904724)
		(width 0.088646)
		(layer "In2.Cu")
		(net "M_B_CPU1_SA_DQS_DN<2>")
	)
	(segment
		(start 71.562468 -277.658322)
		(end 70.419976 -278.800814)
		(width 0.18288)
		(layer "In2.Cu")
		(net "M_B_CPU1_SA_DQS_DN<2>")
	)
	(segment
		(start 72.51446 -276.70633)
		(end 72.126602 -277.094188)
		(width 0.18288)
		(layer "In2.Cu")
		(net "M_B_CPU1_SA_DQS_DN<2>")
	)
	(segment
		(start 60.078112 -287.601406)
		(end 59.87796 -287.801558)
		(width 0.16002)
		(layer "In2.Cu")
		(net "M_B_CPU1_SA_DQS_DN<2>")
	)
	(segment
		(start 75.93457 -273.28622)
		(end 75.758548 -273.28622)
		(width 0.18288)
		(layer "In2.Cu")
		(net "M_B_CPU1_SA_DQS_DN<2>")
	)
	(segment
		(start 49.330102 -293.86657)
		(end 49.313846 -293.86657)
		(width 0.16002)
		(layer "In2.Cu")
		(net "M_B_CPU1_SA_DQS_DN<2>")
	)
	(segment
		(start 50.588164 -294.064436)
		(end 49.527968 -294.064436)
		(width 0.18288)
		(layer "In2.Cu")
		(net "M_B_CPU1_SA_DQS_DN<2>")
	)
	(segment
		(start 71.562468 -277.4823)
		(end 71.562468 -277.658322)
		(width 0.18288)
		(layer "In2.Cu")
		(net "M_B_CPU1_SA_DQS_DN<2>")
	)
	(segment
		(start 66.000122 -284.19298)
		(end 65.971928 -284.221174)
		(width 0.16002)
		(layer "In2.Cu")
		(net "M_B_CPU1_SA_DQS_DN<2>")
	)
	(segment
		(start 69.705982 -280.678636)
		(end 69.317616 -281.067002)
		(width 0.18288)
		(layer "In2.Cu")
		(net "M_B_CPU1_SA_DQS_DN<2>")
	)
	(segment
		(start 74.418444 -274.626324)
		(end 74.418444 -274.802346)
		(width 0.18288)
		(layer "In2.Cu")
		(net "M_B_CPU1_SA_DQS_DN<2>")
	)
	(segment
		(start 75.758548 -273.28622)
		(end 75.370436 -273.674332)
		(width 0.18288)
		(layer "In2.Cu")
		(net "M_B_CPU1_SA_DQS_DN<2>")
	)
	(segment
		(start 77.662532 -271.382236)
		(end 77.27442 -271.770348)
		(width 0.18288)
		(layer "In2.Cu")
		(net "M_B_CPU1_SA_DQS_DN<2>")
	)
	(segment
		(start 79.566516 -269.478252)
		(end 79.178404 -269.866364)
		(width 0.18288)
		(layer "In2.Cu")
		(net "M_B_CPU1_SA_DQS_DN<2>")
	)
	(segment
		(start 72.51446 -276.530308)
		(end 72.51446 -276.70633)
		(width 0.18288)
		(layer "In2.Cu")
		(net "M_B_CPU1_SA_DQS_DN<2>")
	)
	(segment
		(start 52.130452 -294.057832)
		(end 51.62423 -294.057832)
		(width 0.18288)
		(layer "In2.Cu")
		(net "M_B_CPU1_SA_DQS_DN<2>")
	)
	(segment
		(start 58.161174 -291.276786)
		(end 58.144918 -291.276786)
		(width 0.16002)
		(layer "In2.Cu")
		(net "M_B_CPU1_SA_DQS_DN<2>")
	)
	(segment
		(start 58.144918 -291.276786)
		(end 58.116724 -291.30498)
		(width 0.16002)
		(layer "In2.Cu")
		(net "M_B_CPU1_SA_DQS_DN<2>")
	)
	(segment
		(start 76.322428 -272.72234)
		(end 76.322428 -272.898362)
		(width 0.18288)
		(layer "In2.Cu")
		(net "M_B_CPU1_SA_DQS_DN<2>")
	)
	(segment
		(start 49.114202 -293.65067)
		(end 49.086008 -293.622476)
		(width 0.16002)
		(layer "In2.Cu")
		(net "M_B_CPU1_SA_DQS_DN<2>")
	)
	(segment
		(start 76.886562 -272.334228)
		(end 76.71054 -272.334228)
		(width 0.18288)
		(layer "In2.Cu")
		(net "M_B_CPU1_SA_DQS_DN<2>")
	)
	(segment
		(start 77.27442 -271.770348)
		(end 77.27442 -271.94637)
		(width 0.18288)
		(layer "In2.Cu")
		(net "M_B_CPU1_SA_DQS_DN<2>")
	)
	(segment
		(start 71.95058 -277.094188)
		(end 71.562468 -277.4823)
		(width 0.18288)
		(layer "In2.Cu")
		(net "M_B_CPU1_SA_DQS_DN<2>")
	)
	(arc
		(start 87.128096 -265.638534)
		(mid 86.845394 -265.562792)
		(end 86.562692 -265.638534)
		(width 0.088646)
		(layer "In2.Cu")
		(net "M_B_CPU1_SA_DQS_DN<2>")
	)
	(arc
		(start 86.188296 -265.638534)
		(mid 85.905594 -265.562792)
		(end 85.622892 -265.638534)
		(width 0.088646)
		(layer "In2.Cu")
		(net "M_B_CPU1_SA_DQS_DN<2>")
	)
	(arc
		(start 87.502238 -265.638534)
		(mid 87.31515 -265.688677)
		(end 87.128096 -265.638534)
		(width 0.088646)
		(layer "In2.Cu")
		(net "M_B_CPU1_SA_DQS_DN<2>")
	)
	(arc
		(start 85.248496 -265.638534)
		(mid 84.965967 -265.562792)
		(end 84.683346 -265.63828)
		(width 0.088646)
		(layer "In2.Cu")
		(net "M_B_CPU1_SA_DQS_DN<2>")
	)
	(arc
		(start 86.562692 -265.638534)
		(mid 86.375494 -265.688677)
		(end 86.188296 -265.638534)
		(width 0.088646)
		(layer "In2.Cu")
		(net "M_B_CPU1_SA_DQS_DN<2>")
	)
	(arc
		(start 88.03386 -265.49604)
		(mid 87.758661 -265.532272)
		(end 87.502238 -265.638534)
		(width 0.088646)
		(layer "In2.Cu")
		(net "M_B_CPU1_SA_DQS_DN<2>")
	)
	(arc
		(start 83.67268 -265.812524)
		(mid 83.609157 -265.851041)
		(end 83.552538 -265.899138)
		(width 0.088646)
		(layer "In2.Cu")
		(net "M_B_CPU1_SA_DQS_DN<2>")
	)
	(arc
		(start 84.366862 -265.666728)
		(mid 84.206851 -265.632896)
		(end 84.043774 -265.645392)
		(width 0.088646)
		(layer "In2.Cu")
		(net "M_B_CPU1_SA_DQS_DN<2>")
	)
	(arc
		(start 84.6836 -265.639042)
		(mid 84.528309 -265.688107)
		(end 84.366862 -265.666728)
		(width 0.088646)
		(layer "In2.Cu")
		(net "M_B_CPU1_SA_DQS_DN<2>")
	)
	(arc
		(start 84.043774 -265.645392)
		(mid 83.978758 -265.664235)
		(end 83.91652 -265.690858)
		(width 0.088646)
		(layer "In2.Cu")
		(net "M_B_CPU1_SA_DQS_DN<2>")
	)
	(arc
		(start 85.622892 -265.638534)
		(mid 85.435694 -265.688677)
		(end 85.248496 -265.638534)
		(width 0.088646)
		(layer "In2.Cu")
		(net "M_B_CPU1_SA_DQS_DN<2>")
	)
	(segment
		(start 41.29151 -303.130966)
		(end 41.087294 -303.130966)
		(width 0.20066)
		(layer "F.Cu")
		(net "M_B_CPU1_SA_DQS_DN<1>")
	)
	(segment
		(start 91.544648 -272.103342)
		(end 91.544648 -272.639028)
		(width 0.20066)
		(layer "F.Cu")
		(net "M_B_CPU1_SA_DQS_DN<1>")
	)
	(segment
		(start 40.81526 -303.403)
		(end 40.275256 -303.403)
		(width 0.20066)
		(layer "F.Cu")
		(net "M_B_CPU1_SA_DQS_DN<1>")
	)
	(segment
		(start 45.051726 -302.977804)
		(end 44.645072 -302.977804)
		(width 0.20066)
		(layer "F.Cu")
		(net "M_B_CPU1_SA_DQS_DN<1>")
	)
	(segment
		(start 45.312838 -302.716692)
		(end 45.051726 -302.977804)
		(width 0.20066)
		(layer "F.Cu")
		(net "M_B_CPU1_SA_DQS_DN<1>")
	)
	(segment
		(start 44.219876 -303.403)
		(end 44.033186 -303.403)
		(width 0.20066)
		(layer "F.Cu")
		(net "M_B_CPU1_SA_DQS_DN<1>")
	)
	(segment
		(start 41.292272 -303.130966)
		(end 41.29151 -303.130966)
		(width 0.101854)
		(layer "F.Cu")
		(net "M_B_CPU1_SA_DQS_DN<1>")
	)
	(segment
		(start 91.544648 -272.639028)
		(end 91.544394 -272.639282)
		(width 0.20066)
		(layer "F.Cu")
		(net "M_B_CPU1_SA_DQS_DN<1>")
	)
	(segment
		(start 39.125398 -302.977804)
		(end 38.864286 -302.716692)
		(width 0.20066)
		(layer "F.Cu")
		(net "M_B_CPU1_SA_DQS_DN<1>")
	)
	(segment
		(start 44.033186 -303.403)
		(end 43.77182 -303.141634)
		(width 0.20066)
		(layer "F.Cu")
		(net "M_B_CPU1_SA_DQS_DN<1>")
	)
	(segment
		(start 43.616626 -303.141634)
		(end 41.30294 -303.141634)
		(width 0.1016)
		(layer "F.Cu")
		(net "M_B_CPU1_SA_DQS_DN<1>")
	)
	(segment
		(start 45.859446 -302.716692)
		(end 45.312838 -302.716692)
		(width 0.20066)
		(layer "F.Cu")
		(net "M_B_CPU1_SA_DQS_DN<1>")
	)
	(segment
		(start 44.645072 -302.977804)
		(end 44.219876 -303.403)
		(width 0.20066)
		(layer "F.Cu")
		(net "M_B_CPU1_SA_DQS_DN<1>")
	)
	(segment
		(start 40.275256 -303.403)
		(end 39.63924 -302.977804)
		(width 0.20066)
		(layer "F.Cu")
		(net "M_B_CPU1_SA_DQS_DN<1>")
	)
	(segment
		(start 41.087294 -303.130966)
		(end 40.81526 -303.403)
		(width 0.20066)
		(layer "F.Cu")
		(net "M_B_CPU1_SA_DQS_DN<1>")
	)
	(segment
		(start 38.864286 -302.716692)
		(end 38.315646 -302.716692)
		(width 0.20066)
		(layer "F.Cu")
		(net "M_B_CPU1_SA_DQS_DN<1>")
	)
	(segment
		(start 41.30294 -303.141634)
		(end 41.292272 -303.130966)
		(width 0.101854)
		(layer "F.Cu")
		(net "M_B_CPU1_SA_DQS_DN<1>")
	)
	(segment
		(start 43.77182 -303.141634)
		(end 43.616626 -303.141634)
		(width 0.20066)
		(layer "F.Cu")
		(net "M_B_CPU1_SA_DQS_DN<1>")
	)
	(segment
		(start 39.63924 -302.977804)
		(end 39.125398 -302.977804)
		(width 0.20066)
		(layer "F.Cu")
		(net "M_B_CPU1_SA_DQS_DN<1>")
	)
	(segment
		(start 46.964346 -302.716692)
		(end 45.859446 -302.716692)
		(width 0.20066)
		(layer "F.Cu")
		(net "M_B_CPU1_SA_DQS_DN<1>")
	)
	(segment
		(start 75.076558 -288.28238)
		(end 75.144122 -288.44494)
		(width 0.18288)
		(layer "In4.Cu")
		(net "M_B_CPU1_SA_DQS_DN<1>")
	)
	(segment
		(start 78.423262 -282.591764)
		(end 78.423008 -282.767786)
		(width 0.18288)
		(layer "In4.Cu")
		(net "M_B_CPU1_SA_DQS_DN<1>")
	)
	(segment
		(start 79.765144 -281.25293)
		(end 79.376524 -281.640788)
		(width 0.18288)
		(layer "In4.Cu")
		(net "M_B_CPU1_SA_DQS_DN<1>")
	)
	(segment
		(start 84.92871 -276.415246)
		(end 84.92871 -276.9616)
		(width 0.088646)
		(layer "In4.Cu")
		(net "M_B_CPU1_SA_DQS_DN<1>")
	)
	(segment
		(start 82.858102 -278.340566)
		(end 82.680556 -278.517858)
		(width 0.18288)
		(layer "In4.Cu")
		(net "M_B_CPU1_SA_DQS_DN<1>")
	)
	(segment
		(start 81.253584 -279.94356)
		(end 80.894428 -280.302462)
		(width 0.18288)
		(layer "In4.Cu")
		(net "M_B_CPU1_SA_DQS_DN<1>")
	)
	(segment
		(start 61.583062 -299.987716)
		(end 61.049662 -299.987716)
		(width 0.18288)
		(layer "In4.Cu")
		(net "M_B_CPU1_SA_DQS_DN<1>")
	)
	(segment
		(start 80.718406 -280.302208)
		(end 80.329786 -280.690066)
		(width 0.18288)
		(layer "In4.Cu")
		(net "M_B_CPU1_SA_DQS_DN<1>")
	)
	(segment
		(start 82.146648 -279.051258)
		(end 81.787492 -279.41016)
		(width 0.18288)
		(layer "In4.Cu")
		(net "M_B_CPU1_SA_DQS_DN<1>")
	)
	(segment
		(start 74.050906 -290.772342)
		(end 74.118724 -290.934648)
		(width 0.18288)
		(layer "In4.Cu")
		(net "M_B_CPU1_SA_DQS_DN<1>")
	)
	(segment
		(start 75.44816 -287.707324)
		(end 75.285346 -287.774888)
		(width 0.18288)
		(layer "In4.Cu")
		(net "M_B_CPU1_SA_DQS_DN<1>")
	)
	(segment
		(start 51.266598 -303.142904)
		(end 50.868834 -303.142904)
		(width 0.18288)
		(layer "In4.Cu")
		(net "M_B_CPU1_SA_DQS_DN<1>")
	)
	(segment
		(start 66.984118 -299.128942)
		(end 66.599054 -299.128942)
		(width 0.18288)
		(layer "In4.Cu")
		(net "M_B_CPU1_SA_DQS_DN<1>")
	)
	(segment
		(start 86.09203 -274.59178)
		(end 86.086696 -274.594828)
		(width 0.088646)
		(layer "In4.Cu")
		(net "M_B_CPU1_SA_DQS_DN<1>")
	)
	(segment
		(start 81.613248 -279.409906)
		(end 81.253838 -279.769316)
		(width 0.18288)
		(layer "In4.Cu")
		(net "M_B_CPU1_SA_DQS_DN<1>")
	)
	(segment
		(start 50.606452 -303.405286)
		(end 50.22342 -303.405286)
		(width 0.18288)
		(layer "In4.Cu")
		(net "M_B_CPU1_SA_DQS_DN<1>")
	)
	(segment
		(start 91.544394 -272.639282)
		(end 91.512644 -272.755106)
		(width 0.088646)
		(layer "In4.Cu")
		(net "M_B_CPU1_SA_DQS_DN<1>")
	)
	(segment
		(start 75.285346 -287.774888)
		(end 75.076558 -288.28238)
		(width 0.18288)
		(layer "In4.Cu")
		(net "M_B_CPU1_SA_DQS_DN<1>")
	)
	(segment
		(start 83.094322 -278.104346)
		(end 82.858102 -278.340566)
		(width 0.18288)
		(layer "In4.Cu")
		(net "M_B_CPU1_SA_DQS_DN<1>")
	)
	(segment
		(start 66.599054 -299.128942)
		(end 66.361818 -298.891706)
		(width 0.18288)
		(layer "In4.Cu")
		(net "M_B_CPU1_SA_DQS_DN<1>")
	)
	(segment
		(start 87.982806 -272.957544)
		(end 87.972392 -272.96364)
		(width 0.088646)
		(layer "In4.Cu")
		(net "M_B_CPU1_SA_DQS_DN<1>")
	)
	(segment
		(start 74.935334 -288.952178)
		(end 74.77252 -289.019742)
		(width 0.18288)
		(layer "In4.Cu")
		(net "M_B_CPU1_SA_DQS_DN<1>")
	)
	(segment
		(start 80.894428 -280.302462)
		(end 80.718406 -280.302208)
		(width 0.18288)
		(layer "In4.Cu")
		(net "M_B_CPU1_SA_DQS_DN<1>")
	)
	(segment
		(start 83.116674 -278.081994)
		(end 83.094322 -278.104346)
		(width 0.088646)
		(layer "In4.Cu")
		(net "M_B_CPU1_SA_DQS_DN<1>")
	)
	(segment
		(start 89.862406 -272.957544)
		(end 89.851992 -272.96364)
		(width 0.088646)
		(layer "In4.Cu")
		(net "M_B_CPU1_SA_DQS_DN<1>")
	)
	(segment
		(start 82.146902 -278.877014)
		(end 82.146648 -279.051258)
		(width 0.18288)
		(layer "In4.Cu")
		(net "M_B_CPU1_SA_DQS_DN<1>")
	)
	(segment
		(start 50.22342 -303.405286)
		(end 49.542446 -302.724312)
		(width 0.18288)
		(layer "In4.Cu")
		(net "M_B_CPU1_SA_DQS_DN<1>")
	)
	(segment
		(start 73.909936 -291.441886)
		(end 73.747122 -291.50945)
		(width 0.18288)
		(layer "In4.Cu")
		(net "M_B_CPU1_SA_DQS_DN<1>")
	)
	(segment
		(start 49.542446 -302.724312)
		(end 47.933102 -302.724312)
		(width 0.18288)
		(layer "In4.Cu")
		(net "M_B_CPU1_SA_DQS_DN<1>")
	)
	(segment
		(start 86.562946 -273.777456)
		(end 86.562184 -273.777964)
		(width 0.088646)
		(layer "In4.Cu")
		(net "M_B_CPU1_SA_DQS_DN<1>")
	)
	(segment
		(start 79.376524 -281.640788)
		(end 79.37627 -281.81681)
		(width 0.18288)
		(layer "In4.Cu")
		(net "M_B_CPU1_SA_DQS_DN<1>")
	)
	(segment
		(start 64.968374 -299.144436)
		(end 64.085978 -300.026832)
		(width 0.18288)
		(layer "In4.Cu")
		(net "M_B_CPU1_SA_DQS_DN<1>")
	)
	(segment
		(start 76.826364 -284.360874)
		(end 75.44816 -287.707324)
		(width 0.18288)
		(layer "In4.Cu")
		(net "M_B_CPU1_SA_DQS_DN<1>")
	)
	(segment
		(start 77.85862 -283.154882)
		(end 77.47 -283.54274)
		(width 0.18288)
		(layer "In4.Cu")
		(net "M_B_CPU1_SA_DQS_DN<1>")
	)
	(segment
		(start 86.101682 -274.586192)
		(end 86.094316 -274.59051)
		(width 0.088646)
		(layer "In4.Cu")
		(net "M_B_CPU1_SA_DQS_DN<1>")
	)
	(segment
		(start 86.562184 -273.777964)
		(end 86.55685 -273.781012)
		(width 0.088646)
		(layer "In4.Cu")
		(net "M_B_CPU1_SA_DQS_DN<1>")
	)
	(segment
		(start 62.225682 -299.742098)
		(end 61.82868 -299.742098)
		(width 0.18288)
		(layer "In4.Cu")
		(net "M_B_CPU1_SA_DQS_DN<1>")
	)
	(segment
		(start 91.319096 -272.818098)
		(end 91.045538 -272.818098)
		(width 0.088646)
		(layer "In4.Cu")
		(net "M_B_CPU1_SA_DQS_DN<1>")
	)
	(segment
		(start 47.681896 -302.975518)
		(end 47.223172 -302.975518)
		(width 0.18288)
		(layer "In4.Cu")
		(net "M_B_CPU1_SA_DQS_DN<1>")
	)
	(segment
		(start 79.37627 -281.81681)
		(end 78.987904 -282.20416)
		(width 0.18288)
		(layer "In4.Cu")
		(net "M_B_CPU1_SA_DQS_DN<1>")
	)
	(segment
		(start 88.92286 -272.957544)
		(end 88.912446 -272.96364)
		(width 0.088646)
		(layer "In4.Cu")
		(net "M_B_CPU1_SA_DQS_DN<1>")
	)
	(segment
		(start 78.423008 -282.767786)
		(end 78.034642 -283.155136)
		(width 0.18288)
		(layer "In4.Cu")
		(net "M_B_CPU1_SA_DQS_DN<1>")
	)
	(segment
		(start 83.358228 -277.925276)
		(end 83.201002 -278.081994)
		(width 0.088646)
		(layer "In4.Cu")
		(net "M_B_CPU1_SA_DQS_DN<1>")
	)
	(segment
		(start 77.469746 -283.718508)
		(end 77.469746 -283.719016)
		(width 0.18288)
		(layer "In4.Cu")
		(net "M_B_CPU1_SA_DQS_DN<1>")
	)
	(segment
		(start 73.377044 -292.736016)
		(end 66.984118 -299.128942)
		(width 0.18288)
		(layer "In4.Cu")
		(net "M_B_CPU1_SA_DQS_DN<1>")
	)
	(segment
		(start 91.045538 -272.818098)
		(end 90.7923 -272.963894)
		(width 0.088646)
		(layer "In4.Cu")
		(net "M_B_CPU1_SA_DQS_DN<1>")
	)
	(segment
		(start 62.510416 -300.026832)
		(end 62.225682 -299.742098)
		(width 0.18288)
		(layer "In4.Cu")
		(net "M_B_CPU1_SA_DQS_DN<1>")
	)
	(segment
		(start 87.04326 -272.957544)
		(end 87.032846 -272.96364)
		(width 0.088646)
		(layer "In4.Cu")
		(net "M_B_CPU1_SA_DQS_DN<1>")
	)
	(segment
		(start 66.361818 -298.891706)
		(end 65.950846 -298.891706)
		(width 0.18288)
		(layer "In4.Cu")
		(net "M_B_CPU1_SA_DQS_DN<1>")
	)
	(segment
		(start 74.118724 -290.934648)
		(end 73.909936 -291.441886)
		(width 0.18288)
		(layer "In4.Cu")
		(net "M_B_CPU1_SA_DQS_DN<1>")
	)
	(segment
		(start 78.811882 -282.203906)
		(end 78.423262 -282.591764)
		(width 0.18288)
		(layer "In4.Cu")
		(net "M_B_CPU1_SA_DQS_DN<1>")
	)
	(segment
		(start 78.034642 -283.155136)
		(end 77.85862 -283.154882)
		(width 0.18288)
		(layer "In4.Cu")
		(net "M_B_CPU1_SA_DQS_DN<1>")
	)
	(segment
		(start 56.144414 -302.774604)
		(end 54.601364 -303.413668)
		(width 0.18288)
		(layer "In4.Cu")
		(net "M_B_CPU1_SA_DQS_DN<1>")
	)
	(segment
		(start 64.085978 -300.026832)
		(end 62.510416 -300.026832)
		(width 0.18288)
		(layer "In4.Cu")
		(net "M_B_CPU1_SA_DQS_DN<1>")
	)
	(segment
		(start 65.698116 -299.144436)
		(end 64.968374 -299.144436)
		(width 0.18288)
		(layer "In4.Cu")
		(net "M_B_CPU1_SA_DQS_DN<1>")
	)
	(segment
		(start 77.469746 -283.719016)
		(end 76.826364 -284.360874)
		(width 0.18288)
		(layer "In4.Cu")
		(net "M_B_CPU1_SA_DQS_DN<1>")
	)
	(segment
		(start 65.950846 -298.891706)
		(end 65.698116 -299.144436)
		(width 0.18288)
		(layer "In4.Cu")
		(net "M_B_CPU1_SA_DQS_DN<1>")
	)
	(segment
		(start 51.537362 -303.413668)
		(end 51.266598 -303.142904)
		(width 0.18288)
		(layer "In4.Cu")
		(net "M_B_CPU1_SA_DQS_DN<1>")
	)
	(segment
		(start 85.182202 -276.161754)
		(end 84.92871 -276.415246)
		(width 0.088646)
		(layer "In4.Cu")
		(net "M_B_CPU1_SA_DQS_DN<1>")
	)
	(segment
		(start 73.747122 -291.50945)
		(end 73.538334 -292.017196)
		(width 0.18288)
		(layer "In4.Cu")
		(net "M_B_CPU1_SA_DQS_DN<1>")
	)
	(segment
		(start 74.259694 -290.264596)
		(end 74.050906 -290.772342)
		(width 0.18288)
		(layer "In4.Cu")
		(net "M_B_CPU1_SA_DQS_DN<1>")
	)
	(segment
		(start 87.032846 -272.96364)
		(end 87.02675 -272.967196)
		(width 0.088646)
		(layer "In4.Cu")
		(net "M_B_CPU1_SA_DQS_DN<1>")
	)
	(segment
		(start 50.868834 -303.142904)
		(end 50.606452 -303.405286)
		(width 0.18288)
		(layer "In4.Cu")
		(net "M_B_CPU1_SA_DQS_DN<1>")
	)
	(segment
		(start 79.941166 -281.253184)
		(end 79.765144 -281.25293)
		(width 0.18288)
		(layer "In4.Cu")
		(net "M_B_CPU1_SA_DQS_DN<1>")
	)
	(segment
		(start 74.631296 -289.689794)
		(end 74.422508 -290.197032)
		(width 0.18288)
		(layer "In4.Cu")
		(net "M_B_CPU1_SA_DQS_DN<1>")
	)
	(segment
		(start 73.606152 -292.179502)
		(end 73.377044 -292.736016)
		(width 0.18288)
		(layer "In4.Cu")
		(net "M_B_CPU1_SA_DQS_DN<1>")
	)
	(segment
		(start 82.680556 -278.517858)
		(end 82.506312 -278.517604)
		(width 0.18288)
		(layer "In4.Cu")
		(net "M_B_CPU1_SA_DQS_DN<1>")
	)
	(segment
		(start 77.47 -283.54274)
		(end 77.469746 -283.718508)
		(width 0.18288)
		(layer "In4.Cu")
		(net "M_B_CPU1_SA_DQS_DN<1>")
	)
	(segment
		(start 73.538334 -292.017196)
		(end 73.606152 -292.179502)
		(width 0.18288)
		(layer "In4.Cu")
		(net "M_B_CPU1_SA_DQS_DN<1>")
	)
	(segment
		(start 90.7923 -272.963894)
		(end 90.792046 -272.96364)
		(width 0.088646)
		(layer "In4.Cu")
		(net "M_B_CPU1_SA_DQS_DN<1>")
	)
	(segment
		(start 91.512644 -272.755106)
		(end 91.473782 -272.777204)
		(width 0.088646)
		(layer "In4.Cu")
		(net "M_B_CPU1_SA_DQS_DN<1>")
	)
	(segment
		(start 81.787492 -279.41016)
		(end 81.613248 -279.409906)
		(width 0.18288)
		(layer "In4.Cu")
		(net "M_B_CPU1_SA_DQS_DN<1>")
	)
	(segment
		(start 74.422508 -290.197032)
		(end 74.259694 -290.264596)
		(width 0.18288)
		(layer "In4.Cu")
		(net "M_B_CPU1_SA_DQS_DN<1>")
	)
	(segment
		(start 80.329786 -280.690066)
		(end 80.329532 -280.865834)
		(width 0.18288)
		(layer "In4.Cu")
		(net "M_B_CPU1_SA_DQS_DN<1>")
	)
	(segment
		(start 86.750144 -273.453098)
		(end 86.750144 -273.461734)
		(width 0.088646)
		(layer "In4.Cu")
		(net "M_B_CPU1_SA_DQS_DN<1>")
	)
	(segment
		(start 59.409076 -301.084742)
		(end 57.719214 -302.774604)
		(width 0.18288)
		(layer "In4.Cu")
		(net "M_B_CPU1_SA_DQS_DN<1>")
	)
	(segment
		(start 75.144122 -288.44494)
		(end 74.935334 -288.952178)
		(width 0.18288)
		(layer "In4.Cu")
		(net "M_B_CPU1_SA_DQS_DN<1>")
	)
	(segment
		(start 83.201002 -278.081994)
		(end 83.116674 -278.081994)
		(width 0.088646)
		(layer "In4.Cu")
		(net "M_B_CPU1_SA_DQS_DN<1>")
	)
	(segment
		(start 61.049662 -299.987716)
		(end 59.409076 -301.084742)
		(width 0.18288)
		(layer "In4.Cu")
		(net "M_B_CPU1_SA_DQS_DN<1>")
	)
	(segment
		(start 61.82868 -299.742098)
		(end 61.583062 -299.987716)
		(width 0.18288)
		(layer "In4.Cu")
		(net "M_B_CPU1_SA_DQS_DN<1>")
	)
	(segment
		(start 47.933102 -302.724312)
		(end 47.681896 -302.975518)
		(width 0.18288)
		(layer "In4.Cu")
		(net "M_B_CPU1_SA_DQS_DN<1>")
	)
	(segment
		(start 81.253838 -279.769316)
		(end 81.253584 -279.94356)
		(width 0.18288)
		(layer "In4.Cu")
		(net "M_B_CPU1_SA_DQS_DN<1>")
	)
	(segment
		(start 80.329532 -280.865834)
		(end 79.941166 -281.253184)
		(width 0.18288)
		(layer "In4.Cu")
		(net "M_B_CPU1_SA_DQS_DN<1>")
	)
	(segment
		(start 86.092792 -274.591272)
		(end 86.09203 -274.59178)
		(width 0.088646)
		(layer "In4.Cu")
		(net "M_B_CPU1_SA_DQS_DN<1>")
	)
	(segment
		(start 57.719214 -302.774604)
		(end 56.144414 -302.774604)
		(width 0.18288)
		(layer "In4.Cu")
		(net "M_B_CPU1_SA_DQS_DN<1>")
	)
	(segment
		(start 84.92871 -276.9616)
		(end 83.965034 -277.925276)
		(width 0.088646)
		(layer "In4.Cu")
		(net "M_B_CPU1_SA_DQS_DN<1>")
	)
	(segment
		(start 74.77252 -289.019742)
		(end 74.563732 -289.527488)
		(width 0.18288)
		(layer "In4.Cu")
		(net "M_B_CPU1_SA_DQS_DN<1>")
	)
	(segment
		(start 86.094316 -274.59051)
		(end 86.092792 -274.591272)
		(width 0.088646)
		(layer "In4.Cu")
		(net "M_B_CPU1_SA_DQS_DN<1>")
	)
	(segment
		(start 47.223172 -302.975518)
		(end 46.964346 -302.716692)
		(width 0.18288)
		(layer "In4.Cu")
		(net "M_B_CPU1_SA_DQS_DN<1>")
	)
	(segment
		(start 78.987904 -282.20416)
		(end 78.811882 -282.203906)
		(width 0.18288)
		(layer "In4.Cu")
		(net "M_B_CPU1_SA_DQS_DN<1>")
	)
	(segment
		(start 54.601364 -303.413668)
		(end 51.537362 -303.413668)
		(width 0.18288)
		(layer "In4.Cu")
		(net "M_B_CPU1_SA_DQS_DN<1>")
	)
	(segment
		(start 74.563732 -289.527488)
		(end 74.631296 -289.689794)
		(width 0.18288)
		(layer "In4.Cu")
		(net "M_B_CPU1_SA_DQS_DN<1>")
	)
	(segment
		(start 82.506312 -278.517604)
		(end 82.146902 -278.877014)
		(width 0.18288)
		(layer "In4.Cu")
		(net "M_B_CPU1_SA_DQS_DN<1>")
	)
	(segment
		(start 83.965034 -277.925276)
		(end 83.358228 -277.925276)
		(width 0.088646)
		(layer "In4.Cu")
		(net "M_B_CPU1_SA_DQS_DN<1>")
	)
	(segment
		(start 85.631528 -275.400008)
		(end 85.622638 -275.405088)
		(width 0.088646)
		(layer "In4.Cu")
		(net "M_B_CPU1_SA_DQS_DN<1>")
	)
	(arc
		(start 89.851992 -272.96364)
		(mid 89.664794 -273.013783)
		(end 89.477596 -272.96364)
		(width 0.088646)
		(layer "In4.Cu")
		(net "M_B_CPU1_SA_DQS_DN<1>")
	)
	(arc
		(start 86.086696 -274.594828)
		(mid 85.884109 -274.801179)
		(end 85.81009 -275.08073)
		(width 0.088646)
		(layer "In4.Cu")
		(net "M_B_CPU1_SA_DQS_DN<1>")
	)
	(arc
		(start 91.473782 -272.777204)
		(mid 91.399097 -272.807709)
		(end 91.319096 -272.818098)
		(width 0.088646)
		(layer "In4.Cu")
		(net "M_B_CPU1_SA_DQS_DN<1>")
	)
	(arc
		(start 86.55685 -273.781012)
		(mid 86.354263 -273.987363)
		(end 86.280244 -274.266914)
		(width 0.088646)
		(layer "In4.Cu")
		(net "M_B_CPU1_SA_DQS_DN<1>")
	)
	(arc
		(start 85.81009 -275.08073)
		(mid 85.762411 -275.26363)
		(end 85.631528 -275.400008)
		(width 0.088646)
		(layer "In4.Cu")
		(net "M_B_CPU1_SA_DQS_DN<1>")
	)
	(arc
		(start 90.792046 -272.96364)
		(mid 90.604848 -273.013783)
		(end 90.41765 -272.96364)
		(width 0.088646)
		(layer "In4.Cu")
		(net "M_B_CPU1_SA_DQS_DN<1>")
	)
	(arc
		(start 87.972392 -272.96364)
		(mid 87.785194 -273.013783)
		(end 87.597996 -272.96364)
		(width 0.088646)
		(layer "In4.Cu")
		(net "M_B_CPU1_SA_DQS_DN<1>")
	)
	(arc
		(start 87.597996 -272.96364)
		(mid 87.321437 -272.887897)
		(end 87.04326 -272.957544)
		(width 0.088646)
		(layer "In4.Cu")
		(net "M_B_CPU1_SA_DQS_DN<1>")
	)
	(arc
		(start 86.750144 -273.461734)
		(mid 86.697874 -273.644099)
		(end 86.562946 -273.777456)
		(width 0.088646)
		(layer "In4.Cu")
		(net "M_B_CPU1_SA_DQS_DN<1>")
	)
	(arc
		(start 87.02675 -272.967196)
		(mid 86.824163 -273.173547)
		(end 86.750144 -273.453098)
		(width 0.088646)
		(layer "In4.Cu")
		(net "M_B_CPU1_SA_DQS_DN<1>")
	)
	(arc
		(start 85.343746 -275.828252)
		(mid 85.291098 -276.008632)
		(end 85.182202 -276.161754)
		(width 0.088646)
		(layer "In4.Cu")
		(net "M_B_CPU1_SA_DQS_DN<1>")
	)
	(arc
		(start 85.622638 -275.405088)
		(mid 85.433166 -275.58369)
		(end 85.343746 -275.828252)
		(width 0.088646)
		(layer "In4.Cu")
		(net "M_B_CPU1_SA_DQS_DN<1>")
	)
	(arc
		(start 88.912446 -272.96364)
		(mid 88.725248 -273.013783)
		(end 88.53805 -272.96364)
		(width 0.088646)
		(layer "In4.Cu")
		(net "M_B_CPU1_SA_DQS_DN<1>")
	)
	(arc
		(start 89.477596 -272.96364)
		(mid 89.201037 -272.887897)
		(end 88.92286 -272.957544)
		(width 0.088646)
		(layer "In4.Cu")
		(net "M_B_CPU1_SA_DQS_DN<1>")
	)
	(arc
		(start 90.41765 -272.96364)
		(mid 90.140837 -272.88777)
		(end 89.862406 -272.957544)
		(width 0.088646)
		(layer "In4.Cu")
		(net "M_B_CPU1_SA_DQS_DN<1>")
	)
	(arc
		(start 88.53805 -272.96364)
		(mid 88.261237 -272.88777)
		(end 87.982806 -272.957544)
		(width 0.088646)
		(layer "In4.Cu")
		(net "M_B_CPU1_SA_DQS_DN<1>")
	)
	(arc
		(start 86.280244 -274.266914)
		(mid 86.232565 -274.449814)
		(end 86.101682 -274.586192)
		(width 0.088646)
		(layer "In4.Cu")
		(net "M_B_CPU1_SA_DQS_DN<1>")
	)
	(segment
		(start 43.77182 -312.491628)
		(end 43.616626 -312.491628)
		(width 0.20066)
		(layer "F.Cu")
		(net "M_B_CPU1_SA_DQS_DN<0>")
	)
	(segment
		(start 38.864286 -312.066686)
		(end 38.315646 -312.066686)
		(width 0.20066)
		(layer "F.Cu")
		(net "M_B_CPU1_SA_DQS_DN<0>")
	)
	(segment
		(start 44.219876 -312.752994)
		(end 44.033186 -312.752994)
		(width 0.20066)
		(layer "F.Cu")
		(net "M_B_CPU1_SA_DQS_DN<0>")
	)
	(segment
		(start 46.964346 -312.066686)
		(end 45.859446 -312.066686)
		(width 0.20066)
		(layer "F.Cu")
		(net "M_B_CPU1_SA_DQS_DN<0>")
	)
	(segment
		(start 39.125398 -312.327798)
		(end 38.864286 -312.066686)
		(width 0.20066)
		(layer "F.Cu")
		(net "M_B_CPU1_SA_DQS_DN<0>")
	)
	(segment
		(start 43.616626 -312.491628)
		(end 41.30294 -312.491628)
		(width 0.1016)
		(layer "F.Cu")
		(net "M_B_CPU1_SA_DQS_DN<0>")
	)
	(segment
		(start 44.033186 -312.752994)
		(end 43.77182 -312.491628)
		(width 0.20066)
		(layer "F.Cu")
		(net "M_B_CPU1_SA_DQS_DN<0>")
	)
	(segment
		(start 40.81526 -312.752994)
		(end 40.275256 -312.752994)
		(width 0.20066)
		(layer "F.Cu")
		(net "M_B_CPU1_SA_DQS_DN<0>")
	)
	(segment
		(start 88.255094 -274.54479)
		(end 88.255094 -275.08073)
		(width 0.20066)
		(layer "F.Cu")
		(net "M_B_CPU1_SA_DQS_DN<0>")
	)
	(segment
		(start 39.63924 -312.327798)
		(end 39.125398 -312.327798)
		(width 0.20066)
		(layer "F.Cu")
		(net "M_B_CPU1_SA_DQS_DN<0>")
	)
	(segment
		(start 45.312838 -312.066686)
		(end 45.051726 -312.327798)
		(width 0.20066)
		(layer "F.Cu")
		(net "M_B_CPU1_SA_DQS_DN<0>")
	)
	(segment
		(start 44.645072 -312.327798)
		(end 44.219876 -312.752994)
		(width 0.20066)
		(layer "F.Cu")
		(net "M_B_CPU1_SA_DQS_DN<0>")
	)
	(segment
		(start 41.292272 -312.48096)
		(end 41.29151 -312.48096)
		(width 0.101854)
		(layer "F.Cu")
		(net "M_B_CPU1_SA_DQS_DN<0>")
	)
	(segment
		(start 40.275256 -312.752994)
		(end 39.63924 -312.327798)
		(width 0.20066)
		(layer "F.Cu")
		(net "M_B_CPU1_SA_DQS_DN<0>")
	)
	(segment
		(start 45.859446 -312.066686)
		(end 45.312838 -312.066686)
		(width 0.20066)
		(layer "F.Cu")
		(net "M_B_CPU1_SA_DQS_DN<0>")
	)
	(segment
		(start 45.051726 -312.327798)
		(end 44.645072 -312.327798)
		(width 0.20066)
		(layer "F.Cu")
		(net "M_B_CPU1_SA_DQS_DN<0>")
	)
	(segment
		(start 41.087294 -312.48096)
		(end 40.81526 -312.752994)
		(width 0.20066)
		(layer "F.Cu")
		(net "M_B_CPU1_SA_DQS_DN<0>")
	)
	(segment
		(start 41.30294 -312.491628)
		(end 41.292272 -312.48096)
		(width 0.101854)
		(layer "F.Cu")
		(net "M_B_CPU1_SA_DQS_DN<0>")
	)
	(segment
		(start 41.29151 -312.48096)
		(end 41.087294 -312.48096)
		(width 0.20066)
		(layer "F.Cu")
		(net "M_B_CPU1_SA_DQS_DN<0>")
	)
	(segment
		(start 69.060568 -310.087264)
		(end 68.884546 -310.087264)
		(width 0.18288)
		(layer "In2.Cu")
		(net "M_B_CPU1_SA_DQS_DN<0>")
	)
	(segment
		(start 73.914254 -303.978056)
		(end 73.981564 -304.140616)
		(width 0.18288)
		(layer "In2.Cu")
		(net "M_B_CPU1_SA_DQS_DN<0>")
	)
	(segment
		(start 56.525922 -313.93003)
		(end 56.525922 -313.913774)
		(width 0.16002)
		(layer "In2.Cu")
		(net "M_B_CPU1_SA_DQS_DN<0>")
	)
	(segment
		(start 58.129932 -314.264548)
		(end 56.876696 -314.264548)
		(width 0.18288)
		(layer "In2.Cu")
		(net "M_B_CPU1_SA_DQS_DN<0>")
	)
	(segment
		(start 72.692514 -306.279296)
		(end 72.304402 -306.667408)
		(width 0.18288)
		(layer "In2.Cu")
		(net "M_B_CPU1_SA_DQS_DN<0>")
	)
	(segment
		(start 72.868536 -306.279296)
		(end 72.692514 -306.279296)
		(width 0.18288)
		(layer "In2.Cu")
		(net "M_B_CPU1_SA_DQS_DN<0>")
	)
	(segment
		(start 59.914028 -313.257438)
		(end 59.56046 -313.257438)
		(width 0.18288)
		(layer "In2.Cu")
		(net "M_B_CPU1_SA_DQS_DN<0>")
	)
	(segment
		(start 65.704466 -312.533792)
		(end 65.676272 -312.561986)
		(width 0.16002)
		(layer "In2.Cu")
		(net "M_B_CPU1_SA_DQS_DN<0>")
	)
	(segment
		(start 69.448426 -309.699406)
		(end 69.060568 -310.087264)
		(width 0.18288)
		(layer "In2.Cu")
		(net "M_B_CPU1_SA_DQS_DN<0>")
	)
	(segment
		(start 56.741822 -314.129674)
		(end 56.725566 -314.129674)
		(width 0.16002)
		(layer "In2.Cu")
		(net "M_B_CPU1_SA_DQS_DN<0>")
	)
	(segment
		(start 74.506836 -302.872648)
		(end 74.506582 -302.872648)
		(width 0.18288)
		(layer "In2.Cu")
		(net "M_B_CPU1_SA_DQS_DN<0>")
	)
	(segment
		(start 58.865262 -313.529218)
		(end 58.5089 -313.88558)
		(width 0.18288)
		(layer "In2.Cu")
		(net "M_B_CPU1_SA_DQS_DN<0>")
	)
	(segment
		(start 74.506582 -302.872648)
		(end 74.286872 -303.403508)
		(width 0.18288)
		(layer "In2.Cu")
		(net "M_B_CPU1_SA_DQS_DN<0>")
	)
	(segment
		(start 83.214718 -283.929074)
		(end 83.080352 -284.253432)
		(width 0.18288)
		(layer "In2.Cu")
		(net "M_B_CPU1_SA_DQS_DN<0>")
	)
	(segment
		(start 65.920366 -312.317892)
		(end 65.920366 -312.334148)
		(width 0.16002)
		(layer "In2.Cu")
		(net "M_B_CPU1_SA_DQS_DN<0>")
	)
	(segment
		(start 56.770016 -314.157868)
		(end 56.741822 -314.129674)
		(width 0.16002)
		(layer "In2.Cu")
		(net "M_B_CPU1_SA_DQS_DN<0>")
	)
	(segment
		(start 75.908154 -297.645836)
		(end 75.975464 -297.808396)
		(width 0.18288)
		(layer "In2.Cu")
		(net "M_B_CPU1_SA_DQS_DN<0>")
	)
	(segment
		(start 55.416958 -312.80481)
		(end 54.639464 -312.80481)
		(width 0.18288)
		(layer "In2.Cu")
		(net "M_B_CPU1_SA_DQS_DN<0>")
	)
	(segment
		(start 76.796392 -295.82745)
		(end 76.633578 -295.89476)
		(width 0.18288)
		(layer "In2.Cu")
		(net "M_B_CPU1_SA_DQS_DN<0>")
	)
	(segment
		(start 73.608946 -304.714656)
		(end 73.399142 -305.221894)
		(width 0.18288)
		(layer "In2.Cu")
		(net "M_B_CPU1_SA_DQS_DN<0>")
	)
	(segment
		(start 61.576204 -313.41187)
		(end 61.458856 -313.529218)
		(width 0.18288)
		(layer "In2.Cu")
		(net "M_B_CPU1_SA_DQS_DN<0>")
	)
	(segment
		(start 73.77176 -304.647346)
		(end 73.608946 -304.714656)
		(width 0.18288)
		(layer "In2.Cu")
		(net "M_B_CPU1_SA_DQS_DN<0>")
	)
	(segment
		(start 88.255094 -275.08073)
		(end 87.940642 -275.259546)
		(width 0.088646)
		(layer "In2.Cu")
		(net "M_B_CPU1_SA_DQS_DN<0>")
	)
	(segment
		(start 85.218016 -279.869138)
		(end 83.214718 -281.872436)
		(width 0.18288)
		(layer "In2.Cu")
		(net "M_B_CPU1_SA_DQS_DN<0>")
	)
	(segment
		(start 86.09076 -279.46096)
		(end 86.090252 -279.461214)
		(width 0.088646)
		(layer "In2.Cu")
		(net "M_B_CPU1_SA_DQS_DN<0>")
	)
	(segment
		(start 76.49083 -296.564558)
		(end 76.281026 -297.071288)
		(width 0.18288)
		(layer "In2.Cu")
		(net "M_B_CPU1_SA_DQS_DN<0>")
	)
	(segment
		(start 68.496434 -310.651398)
		(end 67.695572 -311.45226)
		(width 0.18288)
		(layer "In2.Cu")
		(net "M_B_CPU1_SA_DQS_DN<0>")
	)
	(segment
		(start 52.669948 -313.30773)
		(end 52.641754 -313.279536)
		(width 0.16002)
		(layer "In2.Cu")
		(net "M_B_CPU1_SA_DQS_DN<0>")
	)
	(segment
		(start 87.903812 -275.259546)
		(end 87.625174 -275.334222)
		(width 0.088646)
		(layer "In2.Cu")
		(net "M_B_CPU1_SA_DQS_DN<0>")
	)
	(segment
		(start 47.47133 -312.358532)
		(end 47.256192 -312.358532)
		(width 0.18288)
		(layer "In2.Cu")
		(net "M_B_CPU1_SA_DQS_DN<0>")
	)
	(segment
		(start 54.029864 -313.41441)
		(end 52.776628 -313.41441)
		(width 0.18288)
		(layer "In2.Cu")
		(net "M_B_CPU1_SA_DQS_DN<0>")
	)
	(segment
		(start 76.281026 -297.071288)
		(end 76.118212 -297.138598)
		(width 0.18288)
		(layer "In2.Cu")
		(net "M_B_CPU1_SA_DQS_DN<0>")
	)
	(segment
		(start 61.820298 -313.184032)
		(end 61.620654 -313.383676)
		(width 0.16002)
		(layer "In2.Cu")
		(net "M_B_CPU1_SA_DQS_DN<0>")
	)
	(segment
		(start 72.304402 -306.667408)
		(end 72.304402 -306.84343)
		(width 0.18288)
		(layer "In2.Cu")
		(net "M_B_CPU1_SA_DQS_DN<0>")
	)
	(segment
		(start 47.256192 -312.358532)
		(end 46.964346 -312.066686)
		(width 0.18288)
		(layer "In2.Cu")
		(net "M_B_CPU1_SA_DQS_DN<0>")
	)
	(segment
		(start 73.466452 -305.384454)
		(end 73.256648 -305.891184)
		(width 0.18288)
		(layer "In2.Cu")
		(net "M_B_CPU1_SA_DQS_DN<0>")
	)
	(segment
		(start 76.118212 -297.138598)
		(end 75.908154 -297.645836)
		(width 0.18288)
		(layer "In2.Cu")
		(net "M_B_CPU1_SA_DQS_DN<0>")
	)
	(segment
		(start 87.980774 -277.842218)
		(end 87.971884 -277.847298)
		(width 0.088646)
		(layer "In2.Cu")
		(net "M_B_CPU1_SA_DQS_DN<0>")
	)
	(segment
		(start 65.476628 -312.76163)
		(end 64.174878 -312.76163)
		(width 0.18288)
		(layer "In2.Cu")
		(net "M_B_CPU1_SA_DQS_DN<0>")
	)
	(segment
		(start 54.164738 -313.279536)
		(end 54.136544 -313.30773)
		(width 0.16002)
		(layer "In2.Cu")
		(net "M_B_CPU1_SA_DQS_DN<0>")
	)
	(segment
		(start 73.256648 -305.891184)
		(end 72.868536 -306.279296)
		(width 0.18288)
		(layer "In2.Cu")
		(net "M_B_CPU1_SA_DQS_DN<0>")
	)
	(segment
		(start 50.55489 -312.790078)
		(end 49.553622 -312.790078)
		(width 0.18288)
		(layer "In2.Cu")
		(net "M_B_CPU1_SA_DQS_DN<0>")
	)
	(segment
		(start 68.884546 -310.087264)
		(end 68.496434 -310.475376)
		(width 0.18288)
		(layer "In2.Cu")
		(net "M_B_CPU1_SA_DQS_DN<0>")
	)
	(segment
		(start 49.358296 -312.594752)
		(end 49.330102 -312.566558)
		(width 0.16002)
		(layer "In2.Cu")
		(net "M_B_CPU1_SA_DQS_DN<0>")
	)
	(segment
		(start 85.302344 -279.869138)
		(end 85.218016 -279.869138)
		(width 0.088646)
		(layer "In2.Cu")
		(net "M_B_CPU1_SA_DQS_DN<0>")
	)
	(segment
		(start 70.964552 -308.18328)
		(end 70.78853 -308.18328)
		(width 0.18288)
		(layer "In2.Cu")
		(net "M_B_CPU1_SA_DQS_DN<0>")
	)
	(segment
		(start 52.425854 -313.079892)
		(end 52.425854 -313.063636)
		(width 0.16002)
		(layer "In2.Cu")
		(net "M_B_CPU1_SA_DQS_DN<0>")
	)
	(segment
		(start 74.286872 -303.403508)
		(end 74.124058 -303.470818)
		(width 0.18288)
		(layer "In2.Cu")
		(net "M_B_CPU1_SA_DQS_DN<0>")
	)
	(segment
		(start 87.940642 -275.259546)
		(end 87.903812 -275.259546)
		(width 0.088646)
		(layer "In2.Cu")
		(net "M_B_CPU1_SA_DQS_DN<0>")
	)
	(segment
		(start 87.0331 -279.474168)
		(end 87.032338 -279.474676)
		(width 0.088646)
		(layer "In2.Cu")
		(net "M_B_CPU1_SA_DQS_DN<0>")
	)
	(segment
		(start 54.380638 -313.079892)
		(end 54.180994 -313.279536)
		(width 0.16002)
		(layer "In2.Cu")
		(net "M_B_CPU1_SA_DQS_DN<0>")
	)
	(segment
		(start 65.920366 -312.334148)
		(end 65.720722 -312.533792)
		(width 0.16002)
		(layer "In2.Cu")
		(net "M_B_CPU1_SA_DQS_DN<0>")
	)
	(segment
		(start 73.981564 -304.140616)
		(end 73.77176 -304.647346)
		(width 0.18288)
		(layer "In2.Cu")
		(net "M_B_CPU1_SA_DQS_DN<0>")
	)
	(segment
		(start 61.820298 -313.167776)
		(end 61.820298 -313.184032)
		(width 0.16002)
		(layer "In2.Cu")
		(net "M_B_CPU1_SA_DQS_DN<0>")
	)
	(segment
		(start 75.76566 -298.315126)
		(end 75.602846 -298.382436)
		(width 0.18288)
		(layer "In2.Cu")
		(net "M_B_CPU1_SA_DQS_DN<0>")
	)
	(segment
		(start 49.313846 -312.566558)
		(end 49.114202 -312.366914)
		(width 0.16002)
		(layer "In2.Cu")
		(net "M_B_CPU1_SA_DQS_DN<0>")
	)
	(segment
		(start 70.01256 -309.135272)
		(end 69.836538 -309.135272)
		(width 0.18288)
		(layer "In2.Cu")
		(net "M_B_CPU1_SA_DQS_DN<0>")
	)
	(segment
		(start 87.035894 -279.47239)
		(end 87.033862 -279.47366)
		(width 0.088646)
		(layer "In2.Cu")
		(net "M_B_CPU1_SA_DQS_DN<0>")
	)
	(segment
		(start 52.625498 -313.279536)
		(end 52.425854 -313.079892)
		(width 0.16002)
		(layer "In2.Cu")
		(net "M_B_CPU1_SA_DQS_DN<0>")
	)
	(segment
		(start 85.959696 -279.577546)
		(end 85.593936 -279.577546)
		(width 0.088646)
		(layer "In2.Cu")
		(net "M_B_CPU1_SA_DQS_DN<0>")
	)
	(segment
		(start 87.033862 -279.47366)
		(end 87.032084 -279.474676)
		(width 0.088646)
		(layer "In2.Cu")
		(net "M_B_CPU1_SA_DQS_DN<0>")
	)
	(segment
		(start 58.5089 -313.88558)
		(end 58.480706 -313.913774)
		(width 0.16002)
		(layer "In2.Cu")
		(net "M_B_CPU1_SA_DQS_DN<0>")
	)
	(segment
		(start 76.633578 -295.89476)
		(end 76.42352 -296.401998)
		(width 0.18288)
		(layer "In2.Cu")
		(net "M_B_CPU1_SA_DQS_DN<0>")
	)
	(segment
		(start 61.604398 -313.383676)
		(end 61.576204 -313.41187)
		(width 0.16002)
		(layer "In2.Cu")
		(net "M_B_CPU1_SA_DQS_DN<0>")
	)
	(segment
		(start 88.159336 -277.511002)
		(end 88.159336 -277.52294)
		(width 0.088646)
		(layer "In2.Cu")
		(net "M_B_CPU1_SA_DQS_DN<0>")
	)
	(segment
		(start 56.525922 -313.913774)
		(end 56.497728 -313.88558)
		(width 0.16002)
		(layer "In2.Cu")
		(net "M_B_CPU1_SA_DQS_DN<0>")
	)
	(segment
		(start 70.78853 -308.18328)
		(end 70.400418 -308.571392)
		(width 0.18288)
		(layer "In2.Cu")
		(net "M_B_CPU1_SA_DQS_DN<0>")
	)
	(segment
		(start 86.66988 -279.481534)
		(end 86.633304 -279.460452)
		(width 0.088646)
		(layer "In2.Cu")
		(net "M_B_CPU1_SA_DQS_DN<0>")
	)
	(segment
		(start 75.392788 -298.88942)
		(end 75.460098 -299.052234)
		(width 0.18288)
		(layer "In2.Cu")
		(net "M_B_CPU1_SA_DQS_DN<0>")
	)
	(segment
		(start 64.174878 -312.76163)
		(end 63.903098 -312.48985)
		(width 0.18288)
		(layer "In2.Cu")
		(net "M_B_CPU1_SA_DQS_DN<0>")
	)
	(segment
		(start 87.625174 -275.334222)
		(end 87.502238 -275.405088)
		(width 0.088646)
		(layer "In2.Cu")
		(net "M_B_CPU1_SA_DQS_DN<0>")
	)
	(segment
		(start 62.226444 -312.76163)
		(end 61.848492 -313.139582)
		(width 0.18288)
		(layer "In2.Cu")
		(net "M_B_CPU1_SA_DQS_DN<0>")
	)
	(segment
		(start 63.903098 -312.48985)
		(end 63.54953 -312.48985)
		(width 0.18288)
		(layer "In2.Cu")
		(net "M_B_CPU1_SA_DQS_DN<0>")
	)
	(segment
		(start 60.185808 -313.529218)
		(end 59.914028 -313.257438)
		(width 0.18288)
		(layer "In2.Cu")
		(net "M_B_CPU1_SA_DQS_DN<0>")
	)
	(segment
		(start 70.400418 -308.747414)
		(end 70.01256 -309.135272)
		(width 0.18288)
		(layer "In2.Cu")
		(net "M_B_CPU1_SA_DQS_DN<0>")
	)
	(segment
		(start 49.330102 -312.566558)
		(end 49.313846 -312.566558)
		(width 0.16002)
		(layer "In2.Cu")
		(net "M_B_CPU1_SA_DQS_DN<0>")
	)
	(segment
		(start 75.460098 -299.052234)
		(end 75.087734 -299.951394)
		(width 0.18288)
		(layer "In2.Cu")
		(net "M_B_CPU1_SA_DQS_DN<0>")
	)
	(segment
		(start 61.848492 -313.139582)
		(end 61.820298 -313.167776)
		(width 0.16002)
		(layer "In2.Cu")
		(net "M_B_CPU1_SA_DQS_DN<0>")
	)
	(segment
		(start 58.236612 -314.157868)
		(end 58.129932 -314.264548)
		(width 0.18288)
		(layer "In2.Cu")
		(net "M_B_CPU1_SA_DQS_DN<0>")
	)
	(segment
		(start 49.553622 -312.790078)
		(end 49.358296 -312.594752)
		(width 0.18288)
		(layer "In2.Cu")
		(net "M_B_CPU1_SA_DQS_DN<0>")
	)
	(segment
		(start 87.032084 -279.474676)
		(end 87.0331 -279.474168)
		(width 0.088646)
		(layer "In2.Cu")
		(net "M_B_CPU1_SA_DQS_DN<0>")
	)
	(segment
		(start 87.50173 -278.661114)
		(end 87.490808 -278.667464)
		(width 0.088646)
		(layer "In2.Cu")
		(net "M_B_CPU1_SA_DQS_DN<0>")
	)
	(segment
		(start 87.043768 -279.468072)
		(end 87.04072 -279.46985)
		(width 0.088646)
		(layer "In2.Cu")
		(net "M_B_CPU1_SA_DQS_DN<0>")
	)
	(segment
		(start 87.03818 -279.47112)
		(end 87.035894 -279.47239)
		(width 0.088646)
		(layer "In2.Cu")
		(net "M_B_CPU1_SA_DQS_DN<0>")
	)
	(segment
		(start 71.740522 -307.231288)
		(end 71.35241 -307.6194)
		(width 0.18288)
		(layer "In2.Cu")
		(net "M_B_CPU1_SA_DQS_DN<0>")
	)
	(segment
		(start 48.846994 -312.08345)
		(end 48.13554 -312.08345)
		(width 0.18288)
		(layer "In2.Cu")
		(net "M_B_CPU1_SA_DQS_DN<0>")
	)
	(segment
		(start 87.971884 -277.847298)
		(end 87.955882 -277.856696)
		(width 0.088646)
		(layer "In2.Cu")
		(net "M_B_CPU1_SA_DQS_DN<0>")
	)
	(segment
		(start 49.086008 -312.322464)
		(end 48.846994 -312.08345)
		(width 0.18288)
		(layer "In2.Cu")
		(net "M_B_CPU1_SA_DQS_DN<0>")
	)
	(segment
		(start 52.39766 -313.035442)
		(end 52.080414 -312.718196)
		(width 0.18288)
		(layer "In2.Cu")
		(net "M_B_CPU1_SA_DQS_DN<0>")
	)
	(segment
		(start 59.56046 -313.257438)
		(end 59.28868 -313.529218)
		(width 0.18288)
		(layer "In2.Cu")
		(net "M_B_CPU1_SA_DQS_DN<0>")
	)
	(segment
		(start 58.480706 -313.913774)
		(end 58.480706 -313.93003)
		(width 0.16002)
		(layer "In2.Cu")
		(net "M_B_CPU1_SA_DQS_DN<0>")
	)
	(segment
		(start 75.975464 -297.808396)
		(end 75.76566 -298.315126)
		(width 0.18288)
		(layer "In2.Cu")
		(net "M_B_CPU1_SA_DQS_DN<0>")
	)
	(segment
		(start 71.916544 -307.231288)
		(end 71.740522 -307.231288)
		(width 0.18288)
		(layer "In2.Cu")
		(net "M_B_CPU1_SA_DQS_DN<0>")
	)
	(segment
		(start 76.42352 -296.401998)
		(end 76.49083 -296.564558)
		(width 0.18288)
		(layer "In2.Cu")
		(net "M_B_CPU1_SA_DQS_DN<0>")
	)
	(segment
		(start 65.676272 -312.561986)
		(end 65.476628 -312.76163)
		(width 0.18288)
		(layer "In2.Cu")
		(net "M_B_CPU1_SA_DQS_DN<0>")
	)
	(segment
		(start 52.425854 -313.063636)
		(end 52.39766 -313.035442)
		(width 0.16002)
		(layer "In2.Cu")
		(net "M_B_CPU1_SA_DQS_DN<0>")
	)
	(segment
		(start 50.85334 -312.491628)
		(end 50.55489 -312.790078)
		(width 0.18288)
		(layer "In2.Cu")
		(net "M_B_CPU1_SA_DQS_DN<0>")
	)
	(segment
		(start 86.049612 -279.49017)
		(end 85.959696 -279.577546)
		(width 0.088646)
		(layer "In2.Cu")
		(net "M_B_CPU1_SA_DQS_DN<0>")
	)
	(segment
		(start 65.720722 -312.533792)
		(end 65.704466 -312.533792)
		(width 0.16002)
		(layer "In2.Cu")
		(net "M_B_CPU1_SA_DQS_DN<0>")
	)
	(segment
		(start 56.497728 -313.88558)
		(end 55.416958 -312.80481)
		(width 0.18288)
		(layer "In2.Cu")
		(net "M_B_CPU1_SA_DQS_DN<0>")
	)
	(segment
		(start 83.080352 -284.253432)
		(end 82.42173 -285.844488)
		(width 0.18288)
		(layer "In2.Cu")
		(net "M_B_CPU1_SA_DQS_DN<0>")
	)
	(segment
		(start 48.13554 -312.08345)
		(end 47.47133 -312.358532)
		(width 0.18288)
		(layer "In2.Cu")
		(net "M_B_CPU1_SA_DQS_DN<0>")
	)
	(segment
		(start 74.124058 -303.470818)
		(end 73.914254 -303.978056)
		(width 0.18288)
		(layer "In2.Cu")
		(net "M_B_CPU1_SA_DQS_DN<0>")
	)
	(segment
		(start 54.136544 -313.30773)
		(end 54.029864 -313.41441)
		(width 0.18288)
		(layer "In2.Cu")
		(net "M_B_CPU1_SA_DQS_DN<0>")
	)
	(segment
		(start 87.51316 -278.65451)
		(end 87.50173 -278.661114)
		(width 0.088646)
		(layer "In2.Cu")
		(net "M_B_CPU1_SA_DQS_DN<0>")
	)
	(segment
		(start 79.87792 -288.388806)
		(end 76.796392 -295.82745)
		(width 0.18288)
		(layer "In2.Cu")
		(net "M_B_CPU1_SA_DQS_DN<0>")
	)
	(segment
		(start 75.602846 -298.382436)
		(end 75.392788 -298.88942)
		(width 0.18288)
		(layer "In2.Cu")
		(net "M_B_CPU1_SA_DQS_DN<0>")
	)
	(segment
		(start 87.21979 -275.876258)
		(end 87.21979 -275.8948)
		(width 0.088646)
		(layer "In2.Cu")
		(net "M_B_CPU1_SA_DQS_DN<0>")
	)
	(segment
		(start 52.080414 -312.718196)
		(end 51.48199 -312.718196)
		(width 0.18288)
		(layer "In2.Cu")
		(net "M_B_CPU1_SA_DQS_DN<0>")
	)
	(segment
		(start 63.27775 -312.76163)
		(end 62.226444 -312.76163)
		(width 0.18288)
		(layer "In2.Cu")
		(net "M_B_CPU1_SA_DQS_DN<0>")
	)
	(segment
		(start 68.496434 -310.475376)
		(end 68.496434 -310.651398)
		(width 0.18288)
		(layer "In2.Cu")
		(net "M_B_CPU1_SA_DQS_DN<0>")
	)
	(segment
		(start 87.21979 -275.8948)
		(end 87.220044 -275.904706)
		(width 0.088646)
		(layer "In2.Cu")
		(net "M_B_CPU1_SA_DQS_DN<0>")
	)
	(segment
		(start 71.35241 -307.6194)
		(end 71.35241 -307.795422)
		(width 0.18288)
		(layer "In2.Cu")
		(net "M_B_CPU1_SA_DQS_DN<0>")
	)
	(segment
		(start 63.54953 -312.48985)
		(end 63.27775 -312.76163)
		(width 0.18288)
		(layer "In2.Cu")
		(net "M_B_CPU1_SA_DQS_DN<0>")
	)
	(segment
		(start 87.689944 -276.708616)
		(end 87.689944 -276.730714)
		(width 0.088646)
		(layer "In2.Cu")
		(net "M_B_CPU1_SA_DQS_DN<0>")
	)
	(segment
		(start 49.114202 -312.350658)
		(end 49.086008 -312.322464)
		(width 0.16002)
		(layer "In2.Cu")
		(net "M_B_CPU1_SA_DQS_DN<0>")
	)
	(segment
		(start 58.281062 -314.129674)
		(end 58.264806 -314.129674)
		(width 0.16002)
		(layer "In2.Cu")
		(net "M_B_CPU1_SA_DQS_DN<0>")
	)
	(segment
		(start 71.35241 -307.795422)
		(end 70.964552 -308.18328)
		(width 0.18288)
		(layer "In2.Cu")
		(net "M_B_CPU1_SA_DQS_DN<0>")
	)
	(segment
		(start 70.400418 -308.571392)
		(end 70.400418 -308.747414)
		(width 0.18288)
		(layer "In2.Cu")
		(net "M_B_CPU1_SA_DQS_DN<0>")
	)
	(segment
		(start 87.502492 -276.384258)
		(end 87.504016 -276.38502)
		(width 0.088646)
		(layer "In2.Cu")
		(net "M_B_CPU1_SA_DQS_DN<0>")
	)
	(segment
		(start 58.480706 -313.93003)
		(end 58.281062 -314.129674)
		(width 0.16002)
		(layer "In2.Cu")
		(net "M_B_CPU1_SA_DQS_DN<0>")
	)
	(segment
		(start 54.408832 -313.035442)
		(end 54.380638 -313.063636)
		(width 0.16002)
		(layer "In2.Cu")
		(net "M_B_CPU1_SA_DQS_DN<0>")
	)
	(segment
		(start 56.876696 -314.264548)
		(end 56.770016 -314.157868)
		(width 0.18288)
		(layer "In2.Cu")
		(net "M_B_CPU1_SA_DQS_DN<0>")
	)
	(segment
		(start 69.836538 -309.135272)
		(end 69.448426 -309.523384)
		(width 0.18288)
		(layer "In2.Cu")
		(net "M_B_CPU1_SA_DQS_DN<0>")
	)
	(segment
		(start 54.380638 -313.063636)
		(end 54.380638 -313.079892)
		(width 0.16002)
		(layer "In2.Cu")
		(net "M_B_CPU1_SA_DQS_DN<0>")
	)
	(segment
		(start 54.639464 -312.80481)
		(end 54.408832 -313.035442)
		(width 0.18288)
		(layer "In2.Cu")
		(net "M_B_CPU1_SA_DQS_DN<0>")
	)
	(segment
		(start 87.504016 -276.38502)
		(end 87.510112 -276.388576)
		(width 0.088646)
		(layer "In2.Cu")
		(net "M_B_CPU1_SA_DQS_DN<0>")
	)
	(segment
		(start 87.04072 -279.46985)
		(end 87.03818 -279.47112)
		(width 0.088646)
		(layer "In2.Cu")
		(net "M_B_CPU1_SA_DQS_DN<0>")
	)
	(segment
		(start 72.304402 -306.84343)
		(end 71.916544 -307.231288)
		(width 0.18288)
		(layer "In2.Cu")
		(net "M_B_CPU1_SA_DQS_DN<0>")
	)
	(segment
		(start 86.052914 -279.48763)
		(end 86.049612 -279.49017)
		(width 0.088646)
		(layer "In2.Cu")
		(net "M_B_CPU1_SA_DQS_DN<0>")
	)
	(segment
		(start 58.264806 -314.129674)
		(end 58.236612 -314.157868)
		(width 0.16002)
		(layer "In2.Cu")
		(net "M_B_CPU1_SA_DQS_DN<0>")
	)
	(segment
		(start 51.48199 -312.718196)
		(end 51.255422 -312.491628)
		(width 0.18288)
		(layer "In2.Cu")
		(net "M_B_CPU1_SA_DQS_DN<0>")
	)
	(segment
		(start 49.114202 -312.366914)
		(end 49.114202 -312.350658)
		(width 0.16002)
		(layer "In2.Cu")
		(net "M_B_CPU1_SA_DQS_DN<0>")
	)
	(segment
		(start 52.776628 -313.41441)
		(end 52.669948 -313.30773)
		(width 0.18288)
		(layer "In2.Cu")
		(net "M_B_CPU1_SA_DQS_DN<0>")
	)
	(segment
		(start 67.695572 -311.45226)
		(end 66.138552 -312.099706)
		(width 0.18288)
		(layer "In2.Cu")
		(net "M_B_CPU1_SA_DQS_DN<0>")
	)
	(segment
		(start 52.641754 -313.279536)
		(end 52.625498 -313.279536)
		(width 0.16002)
		(layer "In2.Cu")
		(net "M_B_CPU1_SA_DQS_DN<0>")
	)
	(segment
		(start 69.448426 -309.523384)
		(end 69.448426 -309.699406)
		(width 0.18288)
		(layer "In2.Cu")
		(net "M_B_CPU1_SA_DQS_DN<0>")
	)
	(segment
		(start 82.42173 -285.844488)
		(end 79.877666 -288.388806)
		(width 0.18288)
		(layer "In2.Cu")
		(net "M_B_CPU1_SA_DQS_DN<0>")
	)
	(segment
		(start 85.593936 -279.577546)
		(end 85.302344 -279.869138)
		(width 0.088646)
		(layer "In2.Cu")
		(net "M_B_CPU1_SA_DQS_DN<0>")
	)
	(segment
		(start 56.725566 -314.129674)
		(end 56.525922 -313.93003)
		(width 0.16002)
		(layer "In2.Cu")
		(net "M_B_CPU1_SA_DQS_DN<0>")
	)
	(segment
		(start 83.214718 -281.872436)
		(end 83.214718 -283.929074)
		(width 0.18288)
		(layer "In2.Cu")
		(net "M_B_CPU1_SA_DQS_DN<0>")
	)
	(segment
		(start 73.399142 -305.221894)
		(end 73.466452 -305.384454)
		(width 0.18288)
		(layer "In2.Cu")
		(net "M_B_CPU1_SA_DQS_DN<0>")
	)
	(segment
		(start 79.877666 -288.388806)
		(end 79.87792 -288.388806)
		(width 0.18288)
		(layer "In2.Cu")
		(net "M_B_CPU1_SA_DQS_DN<0>")
	)
	(segment
		(start 54.180994 -313.279536)
		(end 54.164738 -313.279536)
		(width 0.16002)
		(layer "In2.Cu")
		(net "M_B_CPU1_SA_DQS_DN<0>")
	)
	(segment
		(start 51.255422 -312.491628)
		(end 50.85334 -312.491628)
		(width 0.18288)
		(layer "In2.Cu")
		(net "M_B_CPU1_SA_DQS_DN<0>")
	)
	(segment
		(start 61.458856 -313.529218)
		(end 60.185808 -313.529218)
		(width 0.18288)
		(layer "In2.Cu")
		(net "M_B_CPU1_SA_DQS_DN<0>")
	)
	(segment
		(start 65.94856 -312.289698)
		(end 65.920366 -312.317892)
		(width 0.16002)
		(layer "In2.Cu")
		(net "M_B_CPU1_SA_DQS_DN<0>")
	)
	(segment
		(start 66.138552 -312.099706)
		(end 65.94856 -312.289698)
		(width 0.18288)
		(layer "In2.Cu")
		(net "M_B_CPU1_SA_DQS_DN<0>")
	)
	(segment
		(start 61.620654 -313.383676)
		(end 61.604398 -313.383676)
		(width 0.16002)
		(layer "In2.Cu")
		(net "M_B_CPU1_SA_DQS_DN<0>")
	)
	(segment
		(start 59.28868 -313.529218)
		(end 58.865262 -313.529218)
		(width 0.18288)
		(layer "In2.Cu")
		(net "M_B_CPU1_SA_DQS_DN<0>")
	)
	(segment
		(start 75.087734 -299.951394)
		(end 74.506836 -302.872648)
		(width 0.18288)
		(layer "In2.Cu")
		(net "M_B_CPU1_SA_DQS_DN<0>")
	)
	(arc
		(start 87.502238 -275.405088)
		(mid 87.299952 -275.604069)
		(end 87.21979 -275.876258)
		(width 0.088646)
		(layer "In2.Cu")
		(net "M_B_CPU1_SA_DQS_DN<0>")
	)
	(arc
		(start 87.490808 -278.667464)
		(mid 87.291948 -278.873514)
		(end 87.219536 -279.150572)
		(width 0.088646)
		(layer "In2.Cu")
		(net "M_B_CPU1_SA_DQS_DN<0>")
	)
	(arc
		(start 86.090252 -279.461214)
		(mid 86.070964 -279.473548)
		(end 86.052914 -279.48763)
		(width 0.088646)
		(layer "In2.Cu")
		(net "M_B_CPU1_SA_DQS_DN<0>")
	)
	(arc
		(start 86.633304 -279.460452)
		(mid 86.361973 -279.388025)
		(end 86.09076 -279.46096)
		(width 0.088646)
		(layer "In2.Cu")
		(net "M_B_CPU1_SA_DQS_DN<0>")
	)
	(arc
		(start 87.689944 -276.730714)
		(mid 87.770855 -277.000842)
		(end 87.972138 -277.198328)
		(width 0.088646)
		(layer "In2.Cu")
		(net "M_B_CPU1_SA_DQS_DN<0>")
	)
	(arc
		(start 87.220044 -275.904706)
		(mid 87.298155 -276.181655)
		(end 87.502492 -276.384258)
		(width 0.088646)
		(layer "In2.Cu")
		(net "M_B_CPU1_SA_DQS_DN<0>")
	)
	(arc
		(start 87.972138 -277.198328)
		(mid 88.106296 -277.330383)
		(end 88.159336 -277.511002)
		(width 0.088646)
		(layer "In2.Cu")
		(net "M_B_CPU1_SA_DQS_DN<0>")
	)
	(arc
		(start 88.159336 -277.52294)
		(mid 88.111657 -277.70584)
		(end 87.980774 -277.842218)
		(width 0.088646)
		(layer "In2.Cu")
		(net "M_B_CPU1_SA_DQS_DN<0>")
	)
	(arc
		(start 87.032338 -279.474676)
		(mid 86.851991 -279.524913)
		(end 86.66988 -279.481534)
		(width 0.088646)
		(layer "In2.Cu")
		(net "M_B_CPU1_SA_DQS_DN<0>")
	)
	(arc
		(start 87.510112 -276.388576)
		(mid 87.641923 -276.525059)
		(end 87.689944 -276.708616)
		(width 0.088646)
		(layer "In2.Cu")
		(net "M_B_CPU1_SA_DQS_DN<0>")
	)
	(arc
		(start 87.688928 -278.33701)
		(mid 87.642054 -278.518464)
		(end 87.51316 -278.65451)
		(width 0.088646)
		(layer "In2.Cu")
		(net "M_B_CPU1_SA_DQS_DN<0>")
	)
	(arc
		(start 87.955882 -277.856696)
		(mid 87.760094 -278.062233)
		(end 87.688928 -278.33701)
		(width 0.088646)
		(layer "In2.Cu")
		(net "M_B_CPU1_SA_DQS_DN<0>")
	)
	(arc
		(start 87.219536 -279.150572)
		(mid 87.172662 -279.332026)
		(end 87.043768 -279.468072)
		(width 0.088646)
		(layer "In2.Cu")
		(net "M_B_CPU1_SA_DQS_DN<0>")
	)
	(segment
		(start 40.520112 -305.323494)
		(end 40.36568 -305.477926)
		(width 0.20066)
		(layer "F.Cu")
		(net "M_B_CPU1_SA_DQ<9>")
	)
	(segment
		(start 43.795188 -304.841656)
		(end 43.616626 -304.841656)
		(width 0.20066)
		(layer "F.Cu")
		(net "M_B_CPU1_SA_DQ<9>")
	)
	(segment
		(start 39.649908 -305.266598)
		(end 38.315646 -305.266598)
		(width 0.20066)
		(layer "F.Cu")
		(net "M_B_CPU1_SA_DQ<9>")
	)
	(segment
		(start 45.859446 -305.266598)
		(end 44.22013 -305.266598)
		(width 0.20066)
		(layer "F.Cu")
		(net "M_B_CPU1_SA_DQ<9>")
	)
	(segment
		(start 41.29151 -304.832766)
		(end 40.682672 -304.832766)
		(width 0.20066)
		(layer "F.Cu")
		(net "M_B_CPU1_SA_DQ<9>")
	)
	(segment
		(start 43.285918 -304.841656)
		(end 41.3004 -304.841656)
		(width 0.1016)
		(layer "F.Cu")
		(net "M_B_CPU1_SA_DQ<9>")
	)
	(segment
		(start 40.520112 -304.995326)
		(end 40.520112 -305.323494)
		(width 0.20066)
		(layer "F.Cu")
		(net "M_B_CPU1_SA_DQ<9>")
	)
	(segment
		(start 39.861236 -305.477926)
		(end 39.649908 -305.266598)
		(width 0.20066)
		(layer "F.Cu")
		(net "M_B_CPU1_SA_DQ<9>")
	)
	(segment
		(start 40.682672 -304.832766)
		(end 40.520112 -304.995326)
		(width 0.20066)
		(layer "F.Cu")
		(net "M_B_CPU1_SA_DQ<9>")
	)
	(segment
		(start 44.22013 -305.266598)
		(end 43.795188 -304.841656)
		(width 0.20066)
		(layer "F.Cu")
		(net "M_B_CPU1_SA_DQ<9>")
	)
	(segment
		(start 40.36568 -305.477926)
		(end 39.861236 -305.477926)
		(width 0.20066)
		(layer "F.Cu")
		(net "M_B_CPU1_SA_DQ<9>")
	)
	(segment
		(start 41.3004 -304.841656)
		(end 41.29151 -304.832766)
		(width 0.1016)
		(layer "F.Cu")
		(net "M_B_CPU1_SA_DQ<9>")
	)
	(segment
		(start 43.616626 -304.841656)
		(end 43.285918 -304.841656)
		(width 0.101854)
		(layer "F.Cu")
		(net "M_B_CPU1_SA_DQ<9>")
	)
	(segment
		(start 46.964346 -305.266598)
		(end 45.859446 -305.266598)
		(width 0.20066)
		(layer "F.Cu")
		(net "M_B_CPU1_SA_DQ<9>")
	)
	(arc
		(start 92.014294 -272.917158)
		(mid 92.014357 -273.185128)
		(end 92.014548 -273.453098)
		(width 0.20066)
		(layer "F.Cu")
		(net "M_B_CPU1_SA_DQ<9>")
	)
	(segment
		(start 87.597996 -273.942556)
		(end 87.589106 -273.947636)
		(width 0.088646)
		(layer "In4.Cu")
		(net "M_B_CPU1_SA_DQ<9>")
	)
	(segment
		(start 62.324488 -303.991772)
		(end 59.593988 -303.991772)
		(width 0.18288)
		(layer "In4.Cu")
		(net "M_B_CPU1_SA_DQ<9>")
	)
	(segment
		(start 84.25815 -279.082246)
		(end 77.836268 -285.504128)
		(width 0.18288)
		(layer "In4.Cu")
		(net "M_B_CPU1_SA_DQ<9>")
	)
	(segment
		(start 49.584864 -306.32908)
		(end 49.424844 -306.16906)
		(width 0.18288)
		(layer "In4.Cu")
		(net "M_B_CPU1_SA_DQ<9>")
	)
	(segment
		(start 51.366928 -305.562)
		(end 51.237134 -305.691794)
		(width 0.18288)
		(layer "In4.Cu")
		(net "M_B_CPU1_SA_DQ<9>")
	)
	(segment
		(start 62.62878 -303.68748)
		(end 62.324488 -303.991772)
		(width 0.18288)
		(layer "In4.Cu")
		(net "M_B_CPU1_SA_DQ<9>")
	)
	(segment
		(start 49.264824 -305.74488)
		(end 48.916844 -305.74488)
		(width 0.18288)
		(layer "In4.Cu")
		(net "M_B_CPU1_SA_DQ<9>")
	)
	(segment
		(start 55.115968 -305.691794)
		(end 52.437284 -305.691794)
		(width 0.18288)
		(layer "In4.Cu")
		(net "M_B_CPU1_SA_DQ<9>")
	)
	(segment
		(start 86.188296 -276.384258)
		(end 86.179406 -276.389338)
		(width 0.088646)
		(layer "In4.Cu")
		(net "M_B_CPU1_SA_DQ<9>")
	)
	(segment
		(start 52.30749 -305.562)
		(end 51.366928 -305.562)
		(width 0.18288)
		(layer "In4.Cu")
		(net "M_B_CPU1_SA_DQ<9>")
	)
	(segment
		(start 49.424844 -305.9049)
		(end 49.264824 -305.74488)
		(width 0.18288)
		(layer "In4.Cu")
		(net "M_B_CPU1_SA_DQ<9>")
	)
	(segment
		(start 51.237134 -305.691794)
		(end 50.275744 -305.691794)
		(width 0.18288)
		(layer "In4.Cu")
		(net "M_B_CPU1_SA_DQ<9>")
	)
	(segment
		(start 77.836268 -285.504128)
		(end 74.436986 -293.710868)
		(width 0.18288)
		(layer "In4.Cu")
		(net "M_B_CPU1_SA_DQ<9>")
	)
	(segment
		(start 86.47049 -275.8948)
		(end 86.47049 -275.910294)
		(width 0.088646)
		(layer "In4.Cu")
		(net "M_B_CPU1_SA_DQ<9>")
	)
	(segment
		(start 87.133938 -274.752816)
		(end 87.127842 -274.756372)
		(width 0.088646)
		(layer "In4.Cu")
		(net "M_B_CPU1_SA_DQ<9>")
	)
	(segment
		(start 52.437284 -305.691794)
		(end 52.30749 -305.562)
		(width 0.18288)
		(layer "In4.Cu")
		(net "M_B_CPU1_SA_DQ<9>")
	)
	(segment
		(start 84.457032 -278.883364)
		(end 84.25815 -279.082246)
		(width 0.088646)
		(layer "In4.Cu")
		(net "M_B_CPU1_SA_DQ<9>")
	)
	(segment
		(start 47.389542 -305.691794)
		(end 46.964346 -305.266598)
		(width 0.18288)
		(layer "In4.Cu")
		(net "M_B_CPU1_SA_DQ<9>")
	)
	(segment
		(start 84.457032 -278.437594)
		(end 84.457032 -278.883364)
		(width 0.088646)
		(layer "In4.Cu")
		(net "M_B_CPU1_SA_DQ<9>")
	)
	(segment
		(start 66.706242 -301.441612)
		(end 64.999616 -301.441612)
		(width 0.18288)
		(layer "In4.Cu")
		(net "M_B_CPU1_SA_DQ<9>")
	)
	(segment
		(start 87.127842 -274.756372)
		(end 87.118952 -274.761452)
		(width 0.088646)
		(layer "In4.Cu")
		(net "M_B_CPU1_SA_DQ<9>")
	)
	(segment
		(start 56.157114 -304.650648)
		(end 55.115968 -305.691794)
		(width 0.18288)
		(layer "In4.Cu")
		(net "M_B_CPU1_SA_DQ<9>")
	)
	(segment
		(start 62.62878 -302.97628)
		(end 62.62878 -303.68748)
		(width 0.18288)
		(layer "In4.Cu")
		(net "M_B_CPU1_SA_DQ<9>")
	)
	(segment
		(start 85.718142 -277.198328)
		(end 85.70341 -277.206964)
		(width 0.088646)
		(layer "In4.Cu")
		(net "M_B_CPU1_SA_DQ<9>")
	)
	(segment
		(start 85.66912 -277.225506)
		(end 84.457032 -278.437594)
		(width 0.088646)
		(layer "In4.Cu")
		(net "M_B_CPU1_SA_DQ<9>")
	)
	(segment
		(start 47.883064 -305.691794)
		(end 47.389542 -305.691794)
		(width 0.18288)
		(layer "In4.Cu")
		(net "M_B_CPU1_SA_DQ<9>")
	)
	(segment
		(start 50.275744 -305.691794)
		(end 50.115724 -305.851814)
		(width 0.18288)
		(layer "In4.Cu")
		(net "M_B_CPU1_SA_DQ<9>")
	)
	(segment
		(start 86.657942 -275.570442)
		(end 86.649052 -275.575522)
		(width 0.088646)
		(layer "In4.Cu")
		(net "M_B_CPU1_SA_DQ<9>")
	)
	(segment
		(start 64.999616 -301.441612)
		(end 64.404748 -302.03648)
		(width 0.18288)
		(layer "In4.Cu")
		(net "M_B_CPU1_SA_DQ<9>")
	)
	(segment
		(start 48.551084 -306.324762)
		(end 48.225964 -306.324762)
		(width 0.18288)
		(layer "In4.Cu")
		(net "M_B_CPU1_SA_DQ<9>")
	)
	(segment
		(start 74.436986 -293.710868)
		(end 66.706242 -301.441612)
		(width 0.18288)
		(layer "In4.Cu")
		(net "M_B_CPU1_SA_DQ<9>")
	)
	(segment
		(start 48.043084 -306.141882)
		(end 48.043084 -305.851814)
		(width 0.18288)
		(layer "In4.Cu")
		(net "M_B_CPU1_SA_DQ<9>")
	)
	(segment
		(start 49.932844 -306.32908)
		(end 49.584864 -306.32908)
		(width 0.18288)
		(layer "In4.Cu")
		(net "M_B_CPU1_SA_DQ<9>")
	)
	(segment
		(start 48.043084 -305.851814)
		(end 47.883064 -305.691794)
		(width 0.18288)
		(layer "In4.Cu")
		(net "M_B_CPU1_SA_DQ<9>")
	)
	(segment
		(start 86.000844 -276.708616)
		(end 86.000844 -276.72284)
		(width 0.088646)
		(layer "In4.Cu")
		(net "M_B_CPU1_SA_DQ<9>")
	)
	(segment
		(start 91.774772 -273.552412)
		(end 91.47556 -273.851624)
		(width 0.088646)
		(layer "In4.Cu")
		(net "M_B_CPU1_SA_DQ<9>")
	)
	(segment
		(start 91.35745 -273.942556)
		(end 91.347036 -273.948652)
		(width 0.088646)
		(layer "In4.Cu")
		(net "M_B_CPU1_SA_DQ<9>")
	)
	(segment
		(start 64.404748 -302.03648)
		(end 63.56858 -302.03648)
		(width 0.18288)
		(layer "In4.Cu")
		(net "M_B_CPU1_SA_DQ<9>")
	)
	(segment
		(start 48.733964 -305.92776)
		(end 48.733964 -306.141882)
		(width 0.18288)
		(layer "In4.Cu")
		(net "M_B_CPU1_SA_DQ<9>")
	)
	(segment
		(start 48.225964 -306.324762)
		(end 48.043084 -306.141882)
		(width 0.18288)
		(layer "In4.Cu")
		(net "M_B_CPU1_SA_DQ<9>")
	)
	(segment
		(start 63.56858 -302.03648)
		(end 62.62878 -302.97628)
		(width 0.18288)
		(layer "In4.Cu")
		(net "M_B_CPU1_SA_DQ<9>")
	)
	(segment
		(start 48.733964 -306.141882)
		(end 48.551084 -306.324762)
		(width 0.18288)
		(layer "In4.Cu")
		(net "M_B_CPU1_SA_DQ<9>")
	)
	(segment
		(start 49.424844 -306.16906)
		(end 49.424844 -305.9049)
		(width 0.18288)
		(layer "In4.Cu")
		(net "M_B_CPU1_SA_DQ<9>")
	)
	(segment
		(start 59.593988 -303.991772)
		(end 58.935112 -304.650648)
		(width 0.18288)
		(layer "In4.Cu")
		(net "M_B_CPU1_SA_DQ<9>")
	)
	(segment
		(start 48.916844 -305.74488)
		(end 48.733964 -305.92776)
		(width 0.18288)
		(layer "In4.Cu")
		(net "M_B_CPU1_SA_DQ<9>")
	)
	(segment
		(start 58.935112 -304.650648)
		(end 56.157114 -304.650648)
		(width 0.18288)
		(layer "In4.Cu")
		(net "M_B_CPU1_SA_DQ<9>")
	)
	(segment
		(start 86.94039 -275.08073)
		(end 86.94039 -275.099272)
		(width 0.088646)
		(layer "In4.Cu")
		(net "M_B_CPU1_SA_DQ<9>")
	)
	(segment
		(start 50.115724 -305.851814)
		(end 50.115724 -306.1462)
		(width 0.18288)
		(layer "In4.Cu")
		(net "M_B_CPU1_SA_DQ<9>")
	)
	(segment
		(start 50.115724 -306.1462)
		(end 49.932844 -306.32908)
		(width 0.18288)
		(layer "In4.Cu")
		(net "M_B_CPU1_SA_DQ<9>")
	)
	(arc
		(start 87.118952 -274.761452)
		(mid 86.988038 -274.897812)
		(end 86.94039 -275.08073)
		(width 0.088646)
		(layer "In4.Cu")
		(net "M_B_CPU1_SA_DQ<9>")
	)
	(arc
		(start 91.347036 -273.948652)
		(mid 91.068604 -274.018498)
		(end 90.791792 -273.942556)
		(width 0.088646)
		(layer "In4.Cu")
		(net "M_B_CPU1_SA_DQ<9>")
	)
	(arc
		(start 88.537796 -273.942556)
		(mid 88.255094 -274.018332)
		(end 87.972392 -273.942556)
		(width 0.088646)
		(layer "In4.Cu")
		(net "M_B_CPU1_SA_DQ<9>")
	)
	(arc
		(start 86.649052 -275.575522)
		(mid 86.518138 -275.711882)
		(end 86.47049 -275.8948)
		(width 0.088646)
		(layer "In4.Cu")
		(net "M_B_CPU1_SA_DQ<9>")
	)
	(arc
		(start 87.589106 -273.947636)
		(mid 87.458192 -274.083996)
		(end 87.410544 -274.266914)
		(width 0.088646)
		(layer "In4.Cu")
		(net "M_B_CPU1_SA_DQ<9>")
	)
	(arc
		(start 92.014548 -273.453098)
		(mid 91.884784 -273.47891)
		(end 91.774772 -273.552412)
		(width 0.088646)
		(layer "In4.Cu")
		(net "M_B_CPU1_SA_DQ<9>")
	)
	(arc
		(start 85.68817 -277.215092)
		(mid 85.678546 -277.220118)
		(end 85.66912 -277.225506)
		(width 0.088646)
		(layer "In4.Cu")
		(net "M_B_CPU1_SA_DQ<9>")
	)
	(arc
		(start 86.179406 -276.389338)
		(mid 86.048492 -276.525698)
		(end 86.000844 -276.708616)
		(width 0.088646)
		(layer "In4.Cu")
		(net "M_B_CPU1_SA_DQ<9>")
	)
	(arc
		(start 86.94039 -275.099272)
		(mid 86.860228 -275.371461)
		(end 86.657942 -275.570442)
		(width 0.088646)
		(layer "In4.Cu")
		(net "M_B_CPU1_SA_DQ<9>")
	)
	(arc
		(start 89.477596 -273.942556)
		(mid 89.194894 -274.018332)
		(end 88.912192 -273.942556)
		(width 0.088646)
		(layer "In4.Cu")
		(net "M_B_CPU1_SA_DQ<9>")
	)
	(arc
		(start 91.47556 -273.851624)
		(mid 91.419512 -273.900994)
		(end 91.35745 -273.942556)
		(width 0.088646)
		(layer "In4.Cu")
		(net "M_B_CPU1_SA_DQ<9>")
	)
	(arc
		(start 88.912192 -273.942556)
		(mid 88.724994 -273.892413)
		(end 88.537796 -273.942556)
		(width 0.088646)
		(layer "In4.Cu")
		(net "M_B_CPU1_SA_DQ<9>")
	)
	(arc
		(start 86.47049 -275.910294)
		(mid 86.39112 -276.184028)
		(end 86.188296 -276.384258)
		(width 0.088646)
		(layer "In4.Cu")
		(net "M_B_CPU1_SA_DQ<9>")
	)
	(arc
		(start 85.70341 -277.206964)
		(mid 85.695821 -277.211086)
		(end 85.68817 -277.215092)
		(width 0.088646)
		(layer "In4.Cu")
		(net "M_B_CPU1_SA_DQ<9>")
	)
	(arc
		(start 90.791792 -273.942556)
		(mid 90.604594 -273.892413)
		(end 90.417396 -273.942556)
		(width 0.088646)
		(layer "In4.Cu")
		(net "M_B_CPU1_SA_DQ<9>")
	)
	(arc
		(start 87.972392 -273.942556)
		(mid 87.785194 -273.892413)
		(end 87.597996 -273.942556)
		(width 0.088646)
		(layer "In4.Cu")
		(net "M_B_CPU1_SA_DQ<9>")
	)
	(arc
		(start 86.000844 -276.72284)
		(mid 85.921625 -276.997525)
		(end 85.718142 -277.198328)
		(width 0.088646)
		(layer "In4.Cu")
		(net "M_B_CPU1_SA_DQ<9>")
	)
	(arc
		(start 90.417396 -273.942556)
		(mid 90.134694 -274.018332)
		(end 89.851992 -273.942556)
		(width 0.088646)
		(layer "In4.Cu")
		(net "M_B_CPU1_SA_DQ<9>")
	)
	(arc
		(start 89.851992 -273.942556)
		(mid 89.664794 -273.892413)
		(end 89.477596 -273.942556)
		(width 0.088646)
		(layer "In4.Cu")
		(net "M_B_CPU1_SA_DQ<9>")
	)
	(arc
		(start 87.410544 -274.266914)
		(mid 87.336553 -274.54648)
		(end 87.133938 -274.752816)
		(width 0.088646)
		(layer "In4.Cu")
		(net "M_B_CPU1_SA_DQ<9>")
	)
	(segment
		(start 40.729662 -306.53355)
		(end 40.520112 -306.7431)
		(width 0.20066)
		(layer "F.Cu")
		(net "M_B_CPU1_SA_DQ<8>")
	)
	(segment
		(start 39.888668 -307.20538)
		(end 39.649908 -306.96662)
		(width 0.20066)
		(layer "F.Cu")
		(net "M_B_CPU1_SA_DQ<8>")
	)
	(segment
		(start 45.859446 -306.96662)
		(end 44.490386 -306.96662)
		(width 0.20066)
		(layer "F.Cu")
		(net "M_B_CPU1_SA_DQ<8>")
	)
	(segment
		(start 41.547542 -306.541678)
		(end 41.299638 -306.541678)
		(width 0.101854)
		(layer "F.Cu")
		(net "M_B_CPU1_SA_DQ<8>")
	)
	(segment
		(start 43.616626 -306.541678)
		(end 41.547542 -306.541678)
		(width 0.1016)
		(layer "F.Cu")
		(net "M_B_CPU1_SA_DQ<8>")
	)
	(segment
		(start 40.520112 -307.03266)
		(end 40.347392 -307.20538)
		(width 0.20066)
		(layer "F.Cu")
		(net "M_B_CPU1_SA_DQ<8>")
	)
	(segment
		(start 44.490386 -306.96662)
		(end 44.065444 -306.541678)
		(width 0.20066)
		(layer "F.Cu")
		(net "M_B_CPU1_SA_DQ<8>")
	)
	(segment
		(start 46.964346 -306.96662)
		(end 45.859446 -306.96662)
		(width 0.20066)
		(layer "F.Cu")
		(net "M_B_CPU1_SA_DQ<8>")
	)
	(segment
		(start 40.520112 -306.7431)
		(end 40.520112 -307.03266)
		(width 0.20066)
		(layer "F.Cu")
		(net "M_B_CPU1_SA_DQ<8>")
	)
	(segment
		(start 92.484448 -274.26666)
		(end 92.484194 -274.266914)
		(width 0.20066)
		(layer "F.Cu")
		(net "M_B_CPU1_SA_DQ<8>")
	)
	(segment
		(start 92.484448 -273.730974)
		(end 92.484448 -274.26666)
		(width 0.20066)
		(layer "F.Cu")
		(net "M_B_CPU1_SA_DQ<8>")
	)
	(segment
		(start 44.065444 -306.541678)
		(end 43.616626 -306.541678)
		(width 0.20066)
		(layer "F.Cu")
		(net "M_B_CPU1_SA_DQ<8>")
	)
	(segment
		(start 41.29151 -306.53355)
		(end 40.729662 -306.53355)
		(width 0.20066)
		(layer "F.Cu")
		(net "M_B_CPU1_SA_DQ<8>")
	)
	(segment
		(start 41.299638 -306.541678)
		(end 41.29151 -306.53355)
		(width 0.101854)
		(layer "F.Cu")
		(net "M_B_CPU1_SA_DQ<8>")
	)
	(segment
		(start 40.347392 -307.20538)
		(end 39.888668 -307.20538)
		(width 0.20066)
		(layer "F.Cu")
		(net "M_B_CPU1_SA_DQ<8>")
	)
	(segment
		(start 39.649908 -306.96662)
		(end 38.315646 -306.96662)
		(width 0.20066)
		(layer "F.Cu")
		(net "M_B_CPU1_SA_DQ<8>")
	)
	(segment
		(start 50.004218 -307.391816)
		(end 49.19853 -307.391816)
		(width 0.18288)
		(layer "In4.Cu")
		(net "M_B_CPU1_SA_DQ<8>")
	)
	(segment
		(start 48.53051 -308.05628)
		(end 48.34763 -307.8734)
		(width 0.18288)
		(layer "In4.Cu")
		(net "M_B_CPU1_SA_DQ<8>")
	)
	(segment
		(start 87.41029 -275.8948)
		(end 87.41029 -275.910294)
		(width 0.088646)
		(layer "In4.Cu")
		(net "M_B_CPU1_SA_DQ<8>")
	)
	(segment
		(start 86.940644 -276.708616)
		(end 86.940644 -276.72284)
		(width 0.088646)
		(layer "In4.Cu")
		(net "M_B_CPU1_SA_DQ<8>")
	)
	(segment
		(start 90.332306 -274.762468)
		(end 90.321892 -274.756372)
		(width 0.088646)
		(layer "In4.Cu")
		(net "M_B_CPU1_SA_DQ<8>")
	)
	(segment
		(start 84.970366 -279.794462)
		(end 78.727554 -286.037274)
		(width 0.18288)
		(layer "In4.Cu")
		(net "M_B_CPU1_SA_DQ<8>")
	)
	(segment
		(start 49.19853 -307.391816)
		(end 49.03851 -307.551836)
		(width 0.18288)
		(layer "In4.Cu")
		(net "M_B_CPU1_SA_DQ<8>")
	)
	(segment
		(start 88.067896 -274.756372)
		(end 88.059006 -274.761452)
		(width 0.088646)
		(layer "In4.Cu")
		(net "M_B_CPU1_SA_DQ<8>")
	)
	(segment
		(start 87.597742 -275.570442)
		(end 87.588852 -275.575522)
		(width 0.088646)
		(layer "In4.Cu")
		(net "M_B_CPU1_SA_DQ<8>")
	)
	(segment
		(start 48.34763 -307.551836)
		(end 48.18761 -307.391816)
		(width 0.18288)
		(layer "In4.Cu")
		(net "M_B_CPU1_SA_DQ<8>")
	)
	(segment
		(start 86.657942 -277.198328)
		(end 86.649052 -277.203408)
		(width 0.088646)
		(layer "In4.Cu")
		(net "M_B_CPU1_SA_DQ<8>")
	)
	(segment
		(start 50.854356 -306.541678)
		(end 50.004218 -307.391816)
		(width 0.18288)
		(layer "In4.Cu")
		(net "M_B_CPU1_SA_DQ<8>")
	)
	(segment
		(start 67.3989 -303.000664)
		(end 66.407792 -303.991772)
		(width 0.18288)
		(layer "In4.Cu")
		(net "M_B_CPU1_SA_DQ<8>")
	)
	(segment
		(start 64.508888 -303.991772)
		(end 62.808866 -305.691794)
		(width 0.18288)
		(layer "In4.Cu")
		(net "M_B_CPU1_SA_DQ<8>")
	)
	(segment
		(start 91.833192 -274.752816)
		(end 91.827096 -274.756372)
		(width 0.088646)
		(layer "In4.Cu")
		(net "M_B_CPU1_SA_DQ<8>")
	)
	(segment
		(start 55.132224 -307.293264)
		(end 51.98872 -307.293264)
		(width 0.18288)
		(layer "In4.Cu")
		(net "M_B_CPU1_SA_DQ<8>")
	)
	(segment
		(start 51.98872 -307.293264)
		(end 51.237134 -306.541678)
		(width 0.18288)
		(layer "In4.Cu")
		(net "M_B_CPU1_SA_DQ<8>")
	)
	(segment
		(start 87.128096 -276.384258)
		(end 87.119206 -276.389338)
		(width 0.088646)
		(layer "In4.Cu")
		(net "M_B_CPU1_SA_DQ<8>")
	)
	(segment
		(start 49.03851 -307.551836)
		(end 49.03851 -307.89626)
		(width 0.18288)
		(layer "In4.Cu")
		(net "M_B_CPU1_SA_DQ<8>")
	)
	(segment
		(start 85.905594 -278.219916)
		(end 85.905594 -278.859234)
		(width 0.088646)
		(layer "In4.Cu")
		(net "M_B_CPU1_SA_DQ<8>")
	)
	(segment
		(start 62.808866 -305.691794)
		(end 59.596782 -305.691794)
		(width 0.18288)
		(layer "In4.Cu")
		(net "M_B_CPU1_SA_DQ<8>")
	)
	(segment
		(start 67.3989 -302.362108)
		(end 67.3989 -303.000664)
		(width 0.18288)
		(layer "In4.Cu")
		(net "M_B_CPU1_SA_DQ<8>")
	)
	(segment
		(start 48.34763 -307.8734)
		(end 48.34763 -307.551836)
		(width 0.18288)
		(layer "In4.Cu")
		(net "M_B_CPU1_SA_DQ<8>")
	)
	(segment
		(start 48.87849 -308.05628)
		(end 48.53051 -308.05628)
		(width 0.18288)
		(layer "In4.Cu")
		(net "M_B_CPU1_SA_DQ<8>")
	)
	(segment
		(start 87.880444 -275.08073)
		(end 87.880444 -275.08835)
		(width 0.088646)
		(layer "In4.Cu")
		(net "M_B_CPU1_SA_DQ<8>")
	)
	(segment
		(start 86.47049 -277.522686)
		(end 86.47049 -277.53818)
		(width 0.088646)
		(layer "In4.Cu")
		(net "M_B_CPU1_SA_DQ<8>")
	)
	(segment
		(start 66.407792 -303.991772)
		(end 64.508888 -303.991772)
		(width 0.18288)
		(layer "In4.Cu")
		(net "M_B_CPU1_SA_DQ<8>")
	)
	(segment
		(start 75.195176 -294.565832)
		(end 67.3989 -302.362108)
		(width 0.18288)
		(layer "In4.Cu")
		(net "M_B_CPU1_SA_DQ<8>")
	)
	(segment
		(start 47.389542 -307.391816)
		(end 46.964346 -306.96662)
		(width 0.18288)
		(layer "In4.Cu")
		(net "M_B_CPU1_SA_DQ<8>")
	)
	(segment
		(start 51.237134 -306.541678)
		(end 50.854356 -306.541678)
		(width 0.18288)
		(layer "In4.Cu")
		(net "M_B_CPU1_SA_DQ<8>")
	)
	(segment
		(start 86.058502 -278.067008)
		(end 85.905594 -278.219916)
		(width 0.088646)
		(layer "In4.Cu")
		(net "M_B_CPU1_SA_DQ<8>")
	)
	(segment
		(start 56.039512 -306.385976)
		(end 55.132224 -307.293264)
		(width 0.18288)
		(layer "In4.Cu")
		(net "M_B_CPU1_SA_DQ<8>")
	)
	(segment
		(start 85.905594 -278.859234)
		(end 84.970366 -279.794462)
		(width 0.088646)
		(layer "In4.Cu")
		(net "M_B_CPU1_SA_DQ<8>")
	)
	(segment
		(start 91.827096 -274.756372)
		(end 91.816682 -274.762468)
		(width 0.088646)
		(layer "In4.Cu")
		(net "M_B_CPU1_SA_DQ<8>")
	)
	(segment
		(start 91.907868 -274.709636)
		(end 91.833192 -274.752816)
		(width 0.088646)
		(layer "In4.Cu")
		(net "M_B_CPU1_SA_DQ<8>")
	)
	(segment
		(start 58.9026 -306.385976)
		(end 56.039512 -306.385976)
		(width 0.18288)
		(layer "In4.Cu")
		(net "M_B_CPU1_SA_DQ<8>")
	)
	(segment
		(start 48.18761 -307.391816)
		(end 47.389542 -307.391816)
		(width 0.18288)
		(layer "In4.Cu")
		(net "M_B_CPU1_SA_DQ<8>")
	)
	(segment
		(start 78.727554 -286.037274)
		(end 75.195176 -294.565832)
		(width 0.18288)
		(layer "In4.Cu")
		(net "M_B_CPU1_SA_DQ<8>")
	)
	(segment
		(start 59.596782 -305.691794)
		(end 58.9026 -306.385976)
		(width 0.18288)
		(layer "In4.Cu")
		(net "M_B_CPU1_SA_DQ<8>")
	)
	(segment
		(start 49.03851 -307.89626)
		(end 48.87849 -308.05628)
		(width 0.18288)
		(layer "In4.Cu")
		(net "M_B_CPU1_SA_DQ<8>")
	)
	(arc
		(start 91.261946 -274.756372)
		(mid 91.074748 -274.706229)
		(end 90.88755 -274.756372)
		(width 0.088646)
		(layer "In4.Cu")
		(net "M_B_CPU1_SA_DQ<8>")
	)
	(arc
		(start 91.816682 -274.762468)
		(mid 91.538504 -274.832191)
		(end 91.261946 -274.756372)
		(width 0.088646)
		(layer "In4.Cu")
		(net "M_B_CPU1_SA_DQ<8>")
	)
	(arc
		(start 90.321892 -274.756372)
		(mid 90.134694 -274.706229)
		(end 89.947496 -274.756372)
		(width 0.088646)
		(layer "In4.Cu")
		(net "M_B_CPU1_SA_DQ<8>")
	)
	(arc
		(start 87.119206 -276.389338)
		(mid 86.988292 -276.525698)
		(end 86.940644 -276.708616)
		(width 0.088646)
		(layer "In4.Cu")
		(net "M_B_CPU1_SA_DQ<8>")
	)
	(arc
		(start 92.484194 -274.266914)
		(mid 92.210447 -274.507043)
		(end 91.907868 -274.709636)
		(width 0.088646)
		(layer "In4.Cu")
		(net "M_B_CPU1_SA_DQ<8>")
	)
	(arc
		(start 87.588852 -275.575522)
		(mid 87.457938 -275.711882)
		(end 87.41029 -275.8948)
		(width 0.088646)
		(layer "In4.Cu")
		(net "M_B_CPU1_SA_DQ<8>")
	)
	(arc
		(start 86.47049 -277.53818)
		(mid 86.351246 -277.870184)
		(end 86.058502 -278.067008)
		(width 0.088646)
		(layer "In4.Cu")
		(net "M_B_CPU1_SA_DQ<8>")
	)
	(arc
		(start 86.649052 -277.203408)
		(mid 86.518138 -277.339768)
		(end 86.47049 -277.522686)
		(width 0.088646)
		(layer "In4.Cu")
		(net "M_B_CPU1_SA_DQ<8>")
	)
	(arc
		(start 88.059006 -274.761452)
		(mid 87.928092 -274.897812)
		(end 87.880444 -275.08073)
		(width 0.088646)
		(layer "In4.Cu")
		(net "M_B_CPU1_SA_DQ<8>")
	)
	(arc
		(start 89.382092 -274.756372)
		(mid 89.194894 -274.706229)
		(end 89.007696 -274.756372)
		(width 0.088646)
		(layer "In4.Cu")
		(net "M_B_CPU1_SA_DQ<8>")
	)
	(arc
		(start 90.88755 -274.756372)
		(mid 90.610737 -274.832242)
		(end 90.332306 -274.762468)
		(width 0.088646)
		(layer "In4.Cu")
		(net "M_B_CPU1_SA_DQ<8>")
	)
	(arc
		(start 87.41029 -275.910294)
		(mid 87.33092 -276.184028)
		(end 87.128096 -276.384258)
		(width 0.088646)
		(layer "In4.Cu")
		(net "M_B_CPU1_SA_DQ<8>")
	)
	(arc
		(start 89.947496 -274.756372)
		(mid 89.664794 -274.832148)
		(end 89.382092 -274.756372)
		(width 0.088646)
		(layer "In4.Cu")
		(net "M_B_CPU1_SA_DQ<8>")
	)
	(arc
		(start 87.880444 -275.08835)
		(mid 87.802815 -275.366763)
		(end 87.597742 -275.570442)
		(width 0.088646)
		(layer "In4.Cu")
		(net "M_B_CPU1_SA_DQ<8>")
	)
	(arc
		(start 86.940644 -276.72284)
		(mid 86.861425 -276.997525)
		(end 86.657942 -277.198328)
		(width 0.088646)
		(layer "In4.Cu")
		(net "M_B_CPU1_SA_DQ<8>")
	)
	(arc
		(start 89.007696 -274.756372)
		(mid 88.724994 -274.832148)
		(end 88.442292 -274.756372)
		(width 0.088646)
		(layer "In4.Cu")
		(net "M_B_CPU1_SA_DQ<8>")
	)
	(arc
		(start 88.442292 -274.756372)
		(mid 88.255094 -274.706229)
		(end 88.067896 -274.756372)
		(width 0.088646)
		(layer "In4.Cu")
		(net "M_B_CPU1_SA_DQ<8>")
	)
	(segment
		(start 90.134694 -272.917158)
		(end 90.134694 -273.453098)
		(width 0.20066)
		(layer "F.Cu")
		(net "M_B_CPU1_SA_DQ<7>")
	)
	(segment
		(start 44.735242 -308.255924)
		(end 44.38142 -308.255924)
		(width 0.20066)
		(layer "F.Cu")
		(net "M_B_CPU1_SA_DQ<7>")
	)
	(segment
		(start 47.060358 -308.2417)
		(end 44.987464 -308.2417)
		(width 0.1016)
		(layer "F.Cu")
		(net "M_B_CPU1_SA_DQ<7>")
	)
	(segment
		(start 51.089814 -307.816758)
		(end 49.959514 -307.816758)
		(width 0.20066)
		(layer "F.Cu")
		(net "M_B_CPU1_SA_DQ<7>")
	)
	(segment
		(start 44.987464 -308.2417)
		(end 44.749466 -308.2417)
		(width 0.101854)
		(layer "F.Cu")
		(net "M_B_CPU1_SA_DQ<7>")
	)
	(segment
		(start 48.277526 -307.81244)
		(end 47.882302 -307.81244)
		(width 0.20066)
		(layer "F.Cu")
		(net "M_B_CPU1_SA_DQ<7>")
	)
	(segment
		(start 44.238926 -308.11343)
		(end 44.238926 -307.942742)
		(width 0.20066)
		(layer "F.Cu")
		(net "M_B_CPU1_SA_DQ<7>")
	)
	(segment
		(start 44.38142 -308.255924)
		(end 44.238926 -308.11343)
		(width 0.20066)
		(layer "F.Cu")
		(net "M_B_CPU1_SA_DQ<7>")
	)
	(segment
		(start 47.753778 -307.940964)
		(end 47.753778 -308.092602)
		(width 0.20066)
		(layer "F.Cu")
		(net "M_B_CPU1_SA_DQ<7>")
	)
	(segment
		(start 48.489362 -308.024276)
		(end 48.277526 -307.81244)
		(width 0.20066)
		(layer "F.Cu")
		(net "M_B_CPU1_SA_DQ<7>")
	)
	(segment
		(start 44.749466 -308.2417)
		(end 44.735242 -308.255924)
		(width 0.101854)
		(layer "F.Cu")
		(net "M_B_CPU1_SA_DQ<7>")
	)
	(segment
		(start 49.959514 -307.816758)
		(end 49.143412 -307.816758)
		(width 0.20066)
		(layer "F.Cu")
		(net "M_B_CPU1_SA_DQ<7>")
	)
	(segment
		(start 44.112942 -307.816758)
		(end 42.415714 -307.816758)
		(width 0.20066)
		(layer "F.Cu")
		(net "M_B_CPU1_SA_DQ<7>")
	)
	(segment
		(start 49.143412 -307.816758)
		(end 48.935894 -308.024276)
		(width 0.20066)
		(layer "F.Cu")
		(net "M_B_CPU1_SA_DQ<7>")
	)
	(segment
		(start 47.882302 -307.81244)
		(end 47.753778 -307.940964)
		(width 0.20066)
		(layer "F.Cu")
		(net "M_B_CPU1_SA_DQ<7>")
	)
	(segment
		(start 44.238926 -307.942742)
		(end 44.112942 -307.816758)
		(width 0.20066)
		(layer "F.Cu")
		(net "M_B_CPU1_SA_DQ<7>")
	)
	(segment
		(start 47.60468 -308.2417)
		(end 47.060358 -308.2417)
		(width 0.20066)
		(layer "F.Cu")
		(net "M_B_CPU1_SA_DQ<7>")
	)
	(segment
		(start 47.753778 -308.092602)
		(end 47.60468 -308.2417)
		(width 0.20066)
		(layer "F.Cu")
		(net "M_B_CPU1_SA_DQ<7>")
	)
	(segment
		(start 48.935894 -308.024276)
		(end 48.489362 -308.024276)
		(width 0.20066)
		(layer "F.Cu")
		(net "M_B_CPU1_SA_DQ<7>")
	)
	(segment
		(start 65.324482 -306.808124)
		(end 65.164462 -306.648104)
		(width 0.18288)
		(layer "In2.Cu")
		(net "M_B_CPU1_SA_DQ<7>")
	)
	(segment
		(start 64.699134 -306.648104)
		(end 64.50584 -306.841398)
		(width 0.18288)
		(layer "In2.Cu")
		(net "M_B_CPU1_SA_DQ<7>")
	)
	(segment
		(start 85.152992 -274.591272)
		(end 85.146896 -274.594828)
		(width 0.088646)
		(layer "In2.Cu")
		(net "M_B_CPU1_SA_DQ<7>")
	)
	(segment
		(start 85.34019 -274.266914)
		(end 85.340444 -274.266914)
		(width 0.088646)
		(layer "In2.Cu")
		(net "M_B_CPU1_SA_DQ<7>")
	)
	(segment
		(start 64.50584 -307.263546)
		(end 64.34582 -307.423566)
		(width 0.18288)
		(layer "In2.Cu")
		(net "M_B_CPU1_SA_DQ<7>")
	)
	(segment
		(start 85.623146 -273.777456)
		(end 85.607144 -273.786854)
		(width 0.088646)
		(layer "In2.Cu")
		(net "M_B_CPU1_SA_DQ<7>")
	)
	(segment
		(start 64.039496 -307.423566)
		(end 63.206376 -307.687472)
		(width 0.18288)
		(layer "In2.Cu")
		(net "M_B_CPU1_SA_DQ<7>")
	)
	(segment
		(start 55.26786 -304.49774)
		(end 55.089552 -304.676048)
		(width 0.18288)
		(layer "In2.Cu")
		(net "M_B_CPU1_SA_DQ<7>")
	)
	(segment
		(start 66.233802 -307.659532)
		(end 65.969388 -307.395118)
		(width 0.18288)
		(layer "In2.Cu")
		(net "M_B_CPU1_SA_DQ<7>")
	)
	(segment
		(start 55.089552 -304.676048)
		(end 55.089552 -306.316888)
		(width 0.18288)
		(layer "In2.Cu")
		(net "M_B_CPU1_SA_DQ<7>")
	)
	(segment
		(start 85.810598 -273.443192)
		(end 85.810598 -273.453098)
		(width 0.088646)
		(layer "In2.Cu")
		(net "M_B_CPU1_SA_DQ<7>")
	)
	(segment
		(start 60.807092 -308.261766)
		(end 60.440824 -308.261766)
		(width 0.18288)
		(layer "In2.Cu")
		(net "M_B_CPU1_SA_DQ<7>")
	)
	(segment
		(start 64.50584 -306.841398)
		(end 64.50584 -307.263546)
		(width 0.18288)
		(layer "In2.Cu")
		(net "M_B_CPU1_SA_DQ<7>")
	)
	(segment
		(start 84.565744 -277.12289)
		(end 84.39658 -277.292054)
		(width 0.088646)
		(layer "In2.Cu")
		(net "M_B_CPU1_SA_DQ<7>")
	)
	(segment
		(start 65.324482 -307.230526)
		(end 65.324482 -306.808124)
		(width 0.18288)
		(layer "In2.Cu")
		(net "M_B_CPU1_SA_DQ<7>")
	)
	(segment
		(start 55.80126 -304.67554)
		(end 55.62346 -304.49774)
		(width 0.18288)
		(layer "In2.Cu")
		(net "M_B_CPU1_SA_DQ<7>")
	)
	(segment
		(start 80.691482 -282.510992)
		(end 80.014318 -284.145736)
		(width 0.18288)
		(layer "In2.Cu")
		(net "M_B_CPU1_SA_DQ<7>")
	)
	(segment
		(start 67.208908 -307.659532)
		(end 66.233802 -307.659532)
		(width 0.18288)
		(layer "In2.Cu")
		(net "M_B_CPU1_SA_DQ<7>")
	)
	(segment
		(start 59.198764 -306.526946)
		(end 58.106056 -306.526946)
		(width 0.18288)
		(layer "In2.Cu")
		(net "M_B_CPU1_SA_DQ<7>")
	)
	(segment
		(start 56.029606 -306.526946)
		(end 55.80126 -306.2986)
		(width 0.18288)
		(layer "In2.Cu")
		(net "M_B_CPU1_SA_DQ<7>")
	)
	(segment
		(start 57.218834 -306.872894)
		(end 56.872886 -306.526946)
		(width 0.18288)
		(layer "In2.Cu")
		(net "M_B_CPU1_SA_DQ<7>")
	)
	(segment
		(start 87.987378 -272.955004)
		(end 87.972646 -272.96364)
		(width 0.088646)
		(layer "In2.Cu")
		(net "M_B_CPU1_SA_DQ<7>")
	)
	(segment
		(start 72.484742 -298.34713)
		(end 71.909686 -301.238158)
		(width 0.18288)
		(layer "In2.Cu")
		(net "M_B_CPU1_SA_DQ<7>")
	)
	(segment
		(start 53.090572 -305.70424)
		(end 52.897532 -305.89728)
		(width 0.18288)
		(layer "In2.Cu")
		(net "M_B_CPU1_SA_DQ<7>")
	)
	(segment
		(start 51.855116 -306.587144)
		(end 51.671982 -306.770278)
		(width 0.18288)
		(layer "In2.Cu")
		(net "M_B_CPU1_SA_DQ<7>")
	)
	(segment
		(start 51.671982 -306.770278)
		(end 51.671982 -307.23459)
		(width 0.18288)
		(layer "In2.Cu")
		(net "M_B_CPU1_SA_DQ<7>")
	)
	(segment
		(start 61.449712 -307.89245)
		(end 61.176408 -307.89245)
		(width 0.18288)
		(layer "In2.Cu")
		(net "M_B_CPU1_SA_DQ<7>")
	)
	(segment
		(start 51.671982 -307.23459)
		(end 51.089814 -307.816758)
		(width 0.18288)
		(layer "In2.Cu")
		(net "M_B_CPU1_SA_DQ<7>")
	)
	(segment
		(start 84.691982 -277.027894)
		(end 84.683092 -277.032974)
		(width 0.088646)
		(layer "In2.Cu")
		(net "M_B_CPU1_SA_DQ<7>")
	)
	(segment
		(start 84.012786 -277.733506)
		(end 81.162398 -280.583894)
		(width 0.18288)
		(layer "In2.Cu")
		(net "M_B_CPU1_SA_DQ<7>")
	)
	(segment
		(start 57.760108 -306.872894)
		(end 57.218834 -306.872894)
		(width 0.18288)
		(layer "In2.Cu")
		(net "M_B_CPU1_SA_DQ<7>")
	)
	(segment
		(start 81.162398 -281.374088)
		(end 80.691482 -282.510992)
		(width 0.18288)
		(layer "In2.Cu")
		(net "M_B_CPU1_SA_DQ<7>")
	)
	(segment
		(start 85.161882 -274.586192)
		(end 85.152992 -274.591272)
		(width 0.088646)
		(layer "In2.Cu")
		(net "M_B_CPU1_SA_DQ<7>")
	)
	(segment
		(start 65.969388 -307.395118)
		(end 65.489074 -307.395118)
		(width 0.18288)
		(layer "In2.Cu")
		(net "M_B_CPU1_SA_DQ<7>")
	)
	(segment
		(start 60.440824 -308.261766)
		(end 60.280804 -308.101746)
		(width 0.18288)
		(layer "In2.Cu")
		(net "M_B_CPU1_SA_DQ<7>")
	)
	(segment
		(start 87.047578 -272.955004)
		(end 87.032846 -272.96364)
		(width 0.088646)
		(layer "In2.Cu")
		(net "M_B_CPU1_SA_DQ<7>")
	)
	(segment
		(start 84.39658 -277.349712)
		(end 84.012786 -277.733506)
		(width 0.088646)
		(layer "In2.Cu")
		(net "M_B_CPU1_SA_DQ<7>")
	)
	(segment
		(start 84.39658 -277.292054)
		(end 84.39658 -277.349712)
		(width 0.088646)
		(layer "In2.Cu")
		(net "M_B_CPU1_SA_DQ<7>")
	)
	(segment
		(start 54.829202 -306.577238)
		(end 53.859684 -306.577238)
		(width 0.18288)
		(layer "In2.Cu")
		(net "M_B_CPU1_SA_DQ<7>")
	)
	(segment
		(start 89.821766 -273.453098)
		(end 89.756488 -273.38782)
		(width 0.088646)
		(layer "In2.Cu")
		(net "M_B_CPU1_SA_DQ<7>")
	)
	(segment
		(start 60.280804 -307.608986)
		(end 59.198764 -306.526946)
		(width 0.18288)
		(layer "In2.Cu")
		(net "M_B_CPU1_SA_DQ<7>")
	)
	(segment
		(start 62.611254 -308.282594)
		(end 61.839856 -308.282594)
		(width 0.18288)
		(layer "In2.Cu")
		(net "M_B_CPU1_SA_DQ<7>")
	)
	(segment
		(start 52.737512 -306.587144)
		(end 51.855116 -306.587144)
		(width 0.18288)
		(layer "In2.Cu")
		(net "M_B_CPU1_SA_DQ<7>")
	)
	(segment
		(start 65.489074 -307.395118)
		(end 65.324482 -307.230526)
		(width 0.18288)
		(layer "In2.Cu")
		(net "M_B_CPU1_SA_DQ<7>")
	)
	(segment
		(start 88.92286 -272.957544)
		(end 88.912446 -272.96364)
		(width 0.088646)
		(layer "In2.Cu")
		(net "M_B_CPU1_SA_DQ<7>")
	)
	(segment
		(start 71.909686 -301.238158)
		(end 70.693026 -304.175414)
		(width 0.18288)
		(layer "In2.Cu")
		(net "M_B_CPU1_SA_DQ<7>")
	)
	(segment
		(start 53.506624 -305.70424)
		(end 53.090572 -305.70424)
		(width 0.18288)
		(layer "In2.Cu")
		(net "M_B_CPU1_SA_DQ<7>")
	)
	(segment
		(start 84.676996 -276.380702)
		(end 84.680298 -276.382734)
		(width 0.088646)
		(layer "In2.Cu")
		(net "M_B_CPU1_SA_DQ<7>")
	)
	(segment
		(start 77.202284 -286.95777)
		(end 72.484742 -298.34713)
		(width 0.18288)
		(layer "In2.Cu")
		(net "M_B_CPU1_SA_DQ<7>")
	)
	(segment
		(start 52.897532 -305.89728)
		(end 52.897532 -306.427124)
		(width 0.18288)
		(layer "In2.Cu")
		(net "M_B_CPU1_SA_DQ<7>")
	)
	(segment
		(start 84.691728 -275.400008)
		(end 84.682838 -275.405088)
		(width 0.088646)
		(layer "In2.Cu")
		(net "M_B_CPU1_SA_DQ<7>")
	)
	(segment
		(start 55.80126 -306.2986)
		(end 55.80126 -304.67554)
		(width 0.18288)
		(layer "In2.Cu")
		(net "M_B_CPU1_SA_DQ<7>")
	)
	(segment
		(start 52.897532 -306.427124)
		(end 52.737512 -306.587144)
		(width 0.18288)
		(layer "In2.Cu")
		(net "M_B_CPU1_SA_DQ<7>")
	)
	(segment
		(start 56.872886 -306.526946)
		(end 56.029606 -306.526946)
		(width 0.18288)
		(layer "In2.Cu")
		(net "M_B_CPU1_SA_DQ<7>")
	)
	(segment
		(start 84.683092 -276.384258)
		(end 84.691982 -276.389338)
		(width 0.088646)
		(layer "In2.Cu")
		(net "M_B_CPU1_SA_DQ<7>")
	)
	(segment
		(start 64.34582 -307.423566)
		(end 64.039496 -307.423566)
		(width 0.18288)
		(layer "In2.Cu")
		(net "M_B_CPU1_SA_DQ<7>")
	)
	(segment
		(start 90.134694 -273.453098)
		(end 89.821766 -273.453098)
		(width 0.088646)
		(layer "In2.Cu")
		(net "M_B_CPU1_SA_DQ<7>")
	)
	(segment
		(start 70.693026 -304.175414)
		(end 67.208908 -307.659532)
		(width 0.18288)
		(layer "In2.Cu")
		(net "M_B_CPU1_SA_DQ<7>")
	)
	(segment
		(start 85.632036 -273.772376)
		(end 85.623146 -273.777456)
		(width 0.088646)
		(layer "In2.Cu")
		(net "M_B_CPU1_SA_DQ<7>")
	)
	(segment
		(start 84.40039 -275.876258)
		(end 84.40039 -275.8948)
		(width 0.088646)
		(layer "In2.Cu")
		(net "M_B_CPU1_SA_DQ<7>")
	)
	(segment
		(start 61.839856 -308.282594)
		(end 61.449712 -307.89245)
		(width 0.18288)
		(layer "In2.Cu")
		(net "M_B_CPU1_SA_DQ<7>")
	)
	(segment
		(start 81.162398 -280.583894)
		(end 81.162398 -281.374088)
		(width 0.18288)
		(layer "In2.Cu")
		(net "M_B_CPU1_SA_DQ<7>")
	)
	(segment
		(start 53.699664 -305.89728)
		(end 53.506624 -305.70424)
		(width 0.18288)
		(layer "In2.Cu")
		(net "M_B_CPU1_SA_DQ<7>")
	)
	(segment
		(start 84.680298 -276.382734)
		(end 84.683092 -276.384258)
		(width 0.088646)
		(layer "In2.Cu")
		(net "M_B_CPU1_SA_DQ<7>")
	)
	(segment
		(start 61.176408 -307.89245)
		(end 60.807092 -308.261766)
		(width 0.18288)
		(layer "In2.Cu")
		(net "M_B_CPU1_SA_DQ<7>")
	)
	(segment
		(start 80.014318 -284.145736)
		(end 77.202284 -286.95777)
		(width 0.18288)
		(layer "In2.Cu")
		(net "M_B_CPU1_SA_DQ<7>")
	)
	(segment
		(start 65.164462 -306.648104)
		(end 64.699134 -306.648104)
		(width 0.18288)
		(layer "In2.Cu")
		(net "M_B_CPU1_SA_DQ<7>")
	)
	(segment
		(start 63.206376 -307.687472)
		(end 62.611254 -308.282594)
		(width 0.18288)
		(layer "In2.Cu")
		(net "M_B_CPU1_SA_DQ<7>")
	)
	(segment
		(start 60.280804 -308.101746)
		(end 60.280804 -307.608986)
		(width 0.18288)
		(layer "In2.Cu")
		(net "M_B_CPU1_SA_DQ<7>")
	)
	(segment
		(start 53.699664 -306.417218)
		(end 53.699664 -305.89728)
		(width 0.18288)
		(layer "In2.Cu")
		(net "M_B_CPU1_SA_DQ<7>")
	)
	(segment
		(start 55.089552 -306.316888)
		(end 54.829202 -306.577238)
		(width 0.18288)
		(layer "In2.Cu")
		(net "M_B_CPU1_SA_DQ<7>")
	)
	(segment
		(start 58.106056 -306.526946)
		(end 57.760108 -306.872894)
		(width 0.18288)
		(layer "In2.Cu")
		(net "M_B_CPU1_SA_DQ<7>")
	)
	(segment
		(start 55.62346 -304.49774)
		(end 55.26786 -304.49774)
		(width 0.18288)
		(layer "In2.Cu")
		(net "M_B_CPU1_SA_DQ<7>")
	)
	(segment
		(start 53.859684 -306.577238)
		(end 53.699664 -306.417218)
		(width 0.18288)
		(layer "In2.Cu")
		(net "M_B_CPU1_SA_DQ<7>")
	)
	(arc
		(start 84.87029 -275.08073)
		(mid 84.822611 -275.26363)
		(end 84.691728 -275.400008)
		(width 0.088646)
		(layer "In2.Cu")
		(net "M_B_CPU1_SA_DQ<7>")
	)
	(arc
		(start 85.340444 -274.266914)
		(mid 85.292765 -274.449814)
		(end 85.161882 -274.586192)
		(width 0.088646)
		(layer "In2.Cu")
		(net "M_B_CPU1_SA_DQ<7>")
	)
	(arc
		(start 87.59825 -272.96364)
		(mid 87.324051 -272.887805)
		(end 87.047578 -272.955004)
		(width 0.088646)
		(layer "In2.Cu")
		(net "M_B_CPU1_SA_DQ<7>")
	)
	(arc
		(start 87.032846 -272.96364)
		(mid 86.845648 -273.013783)
		(end 86.65845 -272.96364)
		(width 0.088646)
		(layer "In2.Cu")
		(net "M_B_CPU1_SA_DQ<7>")
	)
	(arc
		(start 86.093046 -272.96364)
		(mid 85.888711 -273.166245)
		(end 85.810598 -273.443192)
		(width 0.088646)
		(layer "In2.Cu")
		(net "M_B_CPU1_SA_DQ<7>")
	)
	(arc
		(start 89.477596 -272.96364)
		(mid 89.201037 -272.887897)
		(end 88.92286 -272.957544)
		(width 0.088646)
		(layer "In2.Cu")
		(net "M_B_CPU1_SA_DQ<7>")
	)
	(arc
		(start 84.682838 -275.405088)
		(mid 84.480552 -275.604069)
		(end 84.40039 -275.876258)
		(width 0.088646)
		(layer "In2.Cu")
		(net "M_B_CPU1_SA_DQ<7>")
	)
	(arc
		(start 88.53805 -272.96364)
		(mid 88.263851 -272.887805)
		(end 87.987378 -272.955004)
		(width 0.088646)
		(layer "In2.Cu")
		(net "M_B_CPU1_SA_DQ<7>")
	)
	(arc
		(start 86.65845 -272.96364)
		(mid 86.375748 -272.887864)
		(end 86.093046 -272.96364)
		(width 0.088646)
		(layer "In2.Cu")
		(net "M_B_CPU1_SA_DQ<7>")
	)
	(arc
		(start 87.972646 -272.96364)
		(mid 87.785448 -273.013783)
		(end 87.59825 -272.96364)
		(width 0.088646)
		(layer "In2.Cu")
		(net "M_B_CPU1_SA_DQ<7>")
	)
	(arc
		(start 84.683092 -277.032974)
		(mid 84.621459 -277.074071)
		(end 84.565744 -277.12289)
		(width 0.088646)
		(layer "In2.Cu")
		(net "M_B_CPU1_SA_DQ<7>")
	)
	(arc
		(start 84.691982 -276.389338)
		(mid 84.870579 -276.708616)
		(end 84.691982 -277.027894)
		(width 0.088646)
		(layer "In2.Cu")
		(net "M_B_CPU1_SA_DQ<7>")
	)
	(arc
		(start 84.40039 -275.8948)
		(mid 84.474381 -276.174366)
		(end 84.676996 -276.380702)
		(width 0.088646)
		(layer "In2.Cu")
		(net "M_B_CPU1_SA_DQ<7>")
	)
	(arc
		(start 85.810598 -273.453098)
		(mid 85.762919 -273.635998)
		(end 85.632036 -273.772376)
		(width 0.088646)
		(layer "In2.Cu")
		(net "M_B_CPU1_SA_DQ<7>")
	)
	(arc
		(start 89.756488 -273.38782)
		(mid 89.667359 -273.142645)
		(end 89.477596 -272.96364)
		(width 0.088646)
		(layer "In2.Cu")
		(net "M_B_CPU1_SA_DQ<7>")
	)
	(arc
		(start 88.912446 -272.96364)
		(mid 88.725248 -273.013783)
		(end 88.53805 -272.96364)
		(width 0.088646)
		(layer "In2.Cu")
		(net "M_B_CPU1_SA_DQ<7>")
	)
	(arc
		(start 85.146896 -274.594828)
		(mid 84.944309 -274.801179)
		(end 84.87029 -275.08073)
		(width 0.088646)
		(layer "In2.Cu")
		(net "M_B_CPU1_SA_DQ<7>")
	)
	(arc
		(start 85.607144 -273.786854)
		(mid 85.411427 -273.992271)
		(end 85.34019 -274.266914)
		(width 0.088646)
		(layer "In2.Cu")
		(net "M_B_CPU1_SA_DQ<7>")
	)
	(segment
		(start 44.735242 -309.081678)
		(end 43.99788 -309.081678)
		(width 0.20066)
		(layer "F.Cu")
		(net "M_B_CPU1_SA_DQ<6>")
	)
	(segment
		(start 51.089814 -309.51678)
		(end 49.959514 -309.51678)
		(width 0.20066)
		(layer "F.Cu")
		(net "M_B_CPU1_SA_DQ<6>")
	)
	(segment
		(start 47.83709 -309.235602)
		(end 47.693326 -309.091838)
		(width 0.20066)
		(layer "F.Cu")
		(net "M_B_CPU1_SA_DQ<6>")
	)
	(segment
		(start 47.060358 -309.091838)
		(end 45.000418 -309.091838)
		(width 0.1016)
		(layer "F.Cu")
		(net "M_B_CPU1_SA_DQ<6>")
	)
	(segment
		(start 47.83709 -309.56123)
		(end 47.83709 -309.235602)
		(width 0.20066)
		(layer "F.Cu")
		(net "M_B_CPU1_SA_DQ<6>")
	)
	(segment
		(start 90.604848 -274.26666)
		(end 90.604594 -274.266914)
		(width 0.20066)
		(layer "F.Cu")
		(net "M_B_CPU1_SA_DQ<6>")
	)
	(segment
		(start 43.562778 -309.51678)
		(end 42.415714 -309.51678)
		(width 0.20066)
		(layer "F.Cu")
		(net "M_B_CPU1_SA_DQ<6>")
	)
	(segment
		(start 48.432974 -309.728616)
		(end 48.004476 -309.728616)
		(width 0.20066)
		(layer "F.Cu")
		(net "M_B_CPU1_SA_DQ<6>")
	)
	(segment
		(start 48.004476 -309.728616)
		(end 47.83709 -309.56123)
		(width 0.20066)
		(layer "F.Cu")
		(net "M_B_CPU1_SA_DQ<6>")
	)
	(segment
		(start 49.959514 -309.51678)
		(end 48.64481 -309.51678)
		(width 0.20066)
		(layer "F.Cu")
		(net "M_B_CPU1_SA_DQ<6>")
	)
	(segment
		(start 44.745402 -309.091838)
		(end 44.735242 -309.081678)
		(width 0.101854)
		(layer "F.Cu")
		(net "M_B_CPU1_SA_DQ<6>")
	)
	(segment
		(start 90.604848 -273.730974)
		(end 90.604848 -274.26666)
		(width 0.20066)
		(layer "F.Cu")
		(net "M_B_CPU1_SA_DQ<6>")
	)
	(segment
		(start 48.64481 -309.51678)
		(end 48.432974 -309.728616)
		(width 0.20066)
		(layer "F.Cu")
		(net "M_B_CPU1_SA_DQ<6>")
	)
	(segment
		(start 43.99788 -309.081678)
		(end 43.562778 -309.51678)
		(width 0.20066)
		(layer "F.Cu")
		(net "M_B_CPU1_SA_DQ<6>")
	)
	(segment
		(start 47.693326 -309.091838)
		(end 47.060358 -309.091838)
		(width 0.20066)
		(layer "F.Cu")
		(net "M_B_CPU1_SA_DQ<6>")
	)
	(segment
		(start 45.000418 -309.091838)
		(end 44.745402 -309.091838)
		(width 0.101854)
		(layer "F.Cu")
		(net "M_B_CPU1_SA_DQ<6>")
	)
	(segment
		(start 57.265824 -308.266084)
		(end 57.072784 -308.459124)
		(width 0.18288)
		(layer "In2.Cu")
		(net "M_B_CPU1_SA_DQ<6>")
	)
	(segment
		(start 88.457278 -273.76882)
		(end 88.442546 -273.777456)
		(width 0.088646)
		(layer "In2.Cu")
		(net "M_B_CPU1_SA_DQ<6>")
	)
	(segment
		(start 63.440056 -309.120032)
		(end 62.349126 -310.210962)
		(width 0.18288)
		(layer "In2.Cu")
		(net "M_B_CPU1_SA_DQ<6>")
	)
	(segment
		(start 64.907414 -308.746398)
		(end 64.53378 -309.120032)
		(width 0.18288)
		(layer "In2.Cu")
		(net "M_B_CPU1_SA_DQ<6>")
	)
	(segment
		(start 87.517224 -273.769074)
		(end 87.502492 -273.777456)
		(width 0.088646)
		(layer "In2.Cu")
		(net "M_B_CPU1_SA_DQ<6>")
	)
	(segment
		(start 85.616796 -276.380702)
		(end 85.620098 -276.382734)
		(width 0.088646)
		(layer "In2.Cu")
		(net "M_B_CPU1_SA_DQ<6>")
	)
	(segment
		(start 86.57336 -273.77136)
		(end 86.562946 -273.777456)
		(width 0.088646)
		(layer "In2.Cu")
		(net "M_B_CPU1_SA_DQ<6>")
	)
	(segment
		(start 84.969604 -277.973282)
		(end 84.759546 -277.973282)
		(width 0.088646)
		(layer "In2.Cu")
		(net "M_B_CPU1_SA_DQ<6>")
	)
	(segment
		(start 56.879744 -309.127906)
		(end 56.171846 -309.127906)
		(width 0.18288)
		(layer "In2.Cu")
		(net "M_B_CPU1_SA_DQ<6>")
	)
	(segment
		(start 54.37632 -308.513988)
		(end 54.37632 -309.00878)
		(width 0.18288)
		(layer "In2.Cu")
		(net "M_B_CPU1_SA_DQ<6>")
	)
	(segment
		(start 81.853278 -280.87955)
		(end 81.853278 -282.361894)
		(width 0.18288)
		(layer "In2.Cu")
		(net "M_B_CPU1_SA_DQ<6>")
	)
	(segment
		(start 62.349126 -310.210962)
		(end 62.076076 -310.210962)
		(width 0.18288)
		(layer "In2.Cu")
		(net "M_B_CPU1_SA_DQ<6>")
	)
	(segment
		(start 53.96357 -309.42153)
		(end 52.884324 -309.42153)
		(width 0.18288)
		(layer "In2.Cu")
		(net "M_B_CPU1_SA_DQ<6>")
	)
	(segment
		(start 85.34019 -275.876258)
		(end 85.34019 -275.8948)
		(width 0.088646)
		(layer "In2.Cu")
		(net "M_B_CPU1_SA_DQ<6>")
	)
	(segment
		(start 57.969404 -309.127906)
		(end 57.776364 -308.934866)
		(width 0.18288)
		(layer "In2.Cu")
		(net "M_B_CPU1_SA_DQ<6>")
	)
	(segment
		(start 71.55561 -304.751994)
		(end 66.941192 -309.366412)
		(width 0.18288)
		(layer "In2.Cu")
		(net "M_B_CPU1_SA_DQ<6>")
	)
	(segment
		(start 58.670444 -309.127906)
		(end 57.969404 -309.127906)
		(width 0.18288)
		(layer "In2.Cu")
		(net "M_B_CPU1_SA_DQ<6>")
	)
	(segment
		(start 51.586384 -309.02021)
		(end 51.089814 -309.51678)
		(width 0.18288)
		(layer "In2.Cu")
		(net "M_B_CPU1_SA_DQ<6>")
	)
	(segment
		(start 59.907678 -310.22417)
		(end 59.186318 -310.22417)
		(width 0.18288)
		(layer "In2.Cu")
		(net "M_B_CPU1_SA_DQ<6>")
	)
	(segment
		(start 57.583324 -308.266084)
		(end 57.265824 -308.266084)
		(width 0.18288)
		(layer "In2.Cu")
		(net "M_B_CPU1_SA_DQ<6>")
	)
	(segment
		(start 81.853278 -282.361894)
		(end 81.20507 -283.926788)
		(width 0.18288)
		(layer "In2.Cu")
		(net "M_B_CPU1_SA_DQ<6>")
	)
	(segment
		(start 55.409084 -310.452262)
		(end 55.165498 -310.208676)
		(width 0.18288)
		(layer "In2.Cu")
		(net "M_B_CPU1_SA_DQ<6>")
	)
	(segment
		(start 55.773066 -310.452262)
		(end 55.409084 -310.452262)
		(width 0.18288)
		(layer "In2.Cu")
		(net "M_B_CPU1_SA_DQ<6>")
	)
	(segment
		(start 90.604594 -274.266914)
		(end 90.291666 -274.266914)
		(width 0.088646)
		(layer "In2.Cu")
		(net "M_B_CPU1_SA_DQ<6>")
	)
	(segment
		(start 55.165498 -310.208676)
		(end 55.165498 -308.475126)
		(width 0.18288)
		(layer "In2.Cu")
		(net "M_B_CPU1_SA_DQ<6>")
	)
	(segment
		(start 86.101682 -274.586192)
		(end 86.092792 -274.591272)
		(width 0.088646)
		(layer "In2.Cu")
		(net "M_B_CPU1_SA_DQ<6>")
	)
	(segment
		(start 73.455022 -298.678346)
		(end 72.885046 -301.543212)
		(width 0.18288)
		(layer "In2.Cu")
		(net "M_B_CPU1_SA_DQ<6>")
	)
	(segment
		(start 85.34019 -277.602696)
		(end 84.969604 -277.973282)
		(width 0.088646)
		(layer "In2.Cu")
		(net "M_B_CPU1_SA_DQ<6>")
	)
	(segment
		(start 85.622892 -276.384258)
		(end 85.631782 -276.389338)
		(width 0.088646)
		(layer "In2.Cu")
		(net "M_B_CPU1_SA_DQ<6>")
	)
	(segment
		(start 52.483004 -309.02021)
		(end 51.586384 -309.02021)
		(width 0.18288)
		(layer "In2.Cu")
		(net "M_B_CPU1_SA_DQ<6>")
	)
	(segment
		(start 81.20507 -283.926788)
		(end 80.853788 -284.774894)
		(width 0.18288)
		(layer "In2.Cu")
		(net "M_B_CPU1_SA_DQ<6>")
	)
	(segment
		(start 86.562946 -273.777456)
		(end 86.55685 -273.781012)
		(width 0.088646)
		(layer "In2.Cu")
		(net "M_B_CPU1_SA_DQ<6>")
	)
	(segment
		(start 78.053946 -287.574736)
		(end 73.455022 -298.678346)
		(width 0.18288)
		(layer "In2.Cu")
		(net "M_B_CPU1_SA_DQ<6>")
	)
	(segment
		(start 66.941192 -309.366412)
		(end 66.227198 -309.366412)
		(width 0.18288)
		(layer "In2.Cu")
		(net "M_B_CPU1_SA_DQ<6>")
	)
	(segment
		(start 85.631782 -277.027894)
		(end 85.622892 -277.032974)
		(width 0.088646)
		(layer "In2.Cu")
		(net "M_B_CPU1_SA_DQ<6>")
	)
	(segment
		(start 57.776364 -308.934866)
		(end 57.776364 -308.459124)
		(width 0.18288)
		(layer "In2.Cu")
		(net "M_B_CPU1_SA_DQ<6>")
	)
	(segment
		(start 56.171846 -309.127906)
		(end 55.978806 -309.320946)
		(width 0.18288)
		(layer "In2.Cu")
		(net "M_B_CPU1_SA_DQ<6>")
	)
	(segment
		(start 55.165498 -308.475126)
		(end 54.972458 -308.282086)
		(width 0.18288)
		(layer "In2.Cu")
		(net "M_B_CPU1_SA_DQ<6>")
	)
	(segment
		(start 65.607184 -308.746398)
		(end 64.907414 -308.746398)
		(width 0.18288)
		(layer "In2.Cu")
		(net "M_B_CPU1_SA_DQ<6>")
	)
	(segment
		(start 57.072784 -308.459124)
		(end 57.072784 -308.934866)
		(width 0.18288)
		(layer "In2.Cu")
		(net "M_B_CPU1_SA_DQ<6>")
	)
	(segment
		(start 62.076076 -310.210962)
		(end 61.525404 -309.66029)
		(width 0.18288)
		(layer "In2.Cu")
		(net "M_B_CPU1_SA_DQ<6>")
	)
	(segment
		(start 58.858658 -309.89651)
		(end 58.858658 -309.31612)
		(width 0.18288)
		(layer "In2.Cu")
		(net "M_B_CPU1_SA_DQ<6>")
	)
	(segment
		(start 87.517478 -273.76882)
		(end 87.517224 -273.769074)
		(width 0.088646)
		(layer "In2.Cu")
		(net "M_B_CPU1_SA_DQ<6>")
	)
	(segment
		(start 66.227198 -309.366412)
		(end 65.607184 -308.746398)
		(width 0.18288)
		(layer "In2.Cu")
		(net "M_B_CPU1_SA_DQ<6>")
	)
	(segment
		(start 57.072784 -308.934866)
		(end 56.879744 -309.127906)
		(width 0.18288)
		(layer "In2.Cu")
		(net "M_B_CPU1_SA_DQ<6>")
	)
	(segment
		(start 59.186318 -310.22417)
		(end 58.858658 -309.89651)
		(width 0.18288)
		(layer "In2.Cu")
		(net "M_B_CPU1_SA_DQ<6>")
	)
	(segment
		(start 89.39276 -273.77136)
		(end 89.382346 -273.777456)
		(width 0.088646)
		(layer "In2.Cu")
		(net "M_B_CPU1_SA_DQ<6>")
	)
	(segment
		(start 85.620098 -276.382734)
		(end 85.622892 -276.384258)
		(width 0.088646)
		(layer "In2.Cu")
		(net "M_B_CPU1_SA_DQ<6>")
	)
	(segment
		(start 54.972458 -308.282086)
		(end 54.608222 -308.282086)
		(width 0.18288)
		(layer "In2.Cu")
		(net "M_B_CPU1_SA_DQ<6>")
	)
	(segment
		(start 55.978806 -310.246522)
		(end 55.773066 -310.452262)
		(width 0.18288)
		(layer "In2.Cu")
		(net "M_B_CPU1_SA_DQ<6>")
	)
	(segment
		(start 64.53378 -309.120032)
		(end 63.440056 -309.120032)
		(width 0.18288)
		(layer "In2.Cu")
		(net "M_B_CPU1_SA_DQ<6>")
	)
	(segment
		(start 84.759546 -277.973282)
		(end 84.506054 -278.226774)
		(width 0.088646)
		(layer "In2.Cu")
		(net "M_B_CPU1_SA_DQ<6>")
	)
	(segment
		(start 54.37632 -309.00878)
		(end 53.96357 -309.42153)
		(width 0.18288)
		(layer "In2.Cu")
		(net "M_B_CPU1_SA_DQ<6>")
	)
	(segment
		(start 58.858658 -309.31612)
		(end 58.670444 -309.127906)
		(width 0.18288)
		(layer "In2.Cu")
		(net "M_B_CPU1_SA_DQ<6>")
	)
	(segment
		(start 60.471558 -309.66029)
		(end 59.907678 -310.22417)
		(width 0.18288)
		(layer "In2.Cu")
		(net "M_B_CPU1_SA_DQ<6>")
	)
	(segment
		(start 54.608222 -308.282086)
		(end 54.37632 -308.513988)
		(width 0.18288)
		(layer "In2.Cu")
		(net "M_B_CPU1_SA_DQ<6>")
	)
	(segment
		(start 52.884324 -309.42153)
		(end 52.483004 -309.02021)
		(width 0.18288)
		(layer "In2.Cu")
		(net "M_B_CPU1_SA_DQ<6>")
	)
	(segment
		(start 55.978806 -309.320946)
		(end 55.978806 -310.246522)
		(width 0.18288)
		(layer "In2.Cu")
		(net "M_B_CPU1_SA_DQ<6>")
	)
	(segment
		(start 85.34019 -277.508462)
		(end 85.34019 -277.602696)
		(width 0.088646)
		(layer "In2.Cu")
		(net "M_B_CPU1_SA_DQ<6>")
	)
	(segment
		(start 84.506054 -278.226774)
		(end 81.853278 -280.87955)
		(width 0.18288)
		(layer "In2.Cu")
		(net "M_B_CPU1_SA_DQ<6>")
	)
	(segment
		(start 61.525404 -309.66029)
		(end 60.471558 -309.66029)
		(width 0.18288)
		(layer "In2.Cu")
		(net "M_B_CPU1_SA_DQ<6>")
	)
	(segment
		(start 90.291666 -274.266914)
		(end 90.226388 -274.201636)
		(width 0.088646)
		(layer "In2.Cu")
		(net "M_B_CPU1_SA_DQ<6>")
	)
	(segment
		(start 85.631528 -275.400008)
		(end 85.622638 -275.405088)
		(width 0.088646)
		(layer "In2.Cu")
		(net "M_B_CPU1_SA_DQ<6>")
	)
	(segment
		(start 86.092792 -274.591272)
		(end 86.086696 -274.594828)
		(width 0.088646)
		(layer "In2.Cu")
		(net "M_B_CPU1_SA_DQ<6>")
	)
	(segment
		(start 57.776364 -308.459124)
		(end 57.583324 -308.266084)
		(width 0.18288)
		(layer "In2.Cu")
		(net "M_B_CPU1_SA_DQ<6>")
	)
	(segment
		(start 80.853788 -284.774894)
		(end 78.053946 -287.574736)
		(width 0.18288)
		(layer "In2.Cu")
		(net "M_B_CPU1_SA_DQ<6>")
	)
	(segment
		(start 72.885046 -301.543212)
		(end 71.55561 -304.751994)
		(width 0.18288)
		(layer "In2.Cu")
		(net "M_B_CPU1_SA_DQ<6>")
	)
	(arc
		(start 88.06815 -273.777456)
		(mid 87.793951 -273.701621)
		(end 87.517478 -273.76882)
		(width 0.088646)
		(layer "In2.Cu")
		(net "M_B_CPU1_SA_DQ<6>")
	)
	(arc
		(start 87.128096 -273.777456)
		(mid 86.851537 -273.701713)
		(end 86.57336 -273.77136)
		(width 0.088646)
		(layer "In2.Cu")
		(net "M_B_CPU1_SA_DQ<6>")
	)
	(arc
		(start 89.382346 -273.777456)
		(mid 89.195148 -273.827599)
		(end 89.00795 -273.777456)
		(width 0.088646)
		(layer "In2.Cu")
		(net "M_B_CPU1_SA_DQ<6>")
	)
	(arc
		(start 85.631782 -276.389338)
		(mid 85.810379 -276.708616)
		(end 85.631782 -277.027894)
		(width 0.088646)
		(layer "In2.Cu")
		(net "M_B_CPU1_SA_DQ<6>")
	)
	(arc
		(start 86.55685 -273.781012)
		(mid 86.354263 -273.987363)
		(end 86.280244 -274.266914)
		(width 0.088646)
		(layer "In2.Cu")
		(net "M_B_CPU1_SA_DQ<6>")
	)
	(arc
		(start 85.622892 -277.032974)
		(mid 85.419411 -277.233778)
		(end 85.34019 -277.508462)
		(width 0.088646)
		(layer "In2.Cu")
		(net "M_B_CPU1_SA_DQ<6>")
	)
	(arc
		(start 90.226388 -274.201636)
		(mid 90.137259 -273.956461)
		(end 89.947496 -273.777456)
		(width 0.088646)
		(layer "In2.Cu")
		(net "M_B_CPU1_SA_DQ<6>")
	)
	(arc
		(start 86.280244 -274.266914)
		(mid 86.232565 -274.449814)
		(end 86.101682 -274.586192)
		(width 0.088646)
		(layer "In2.Cu")
		(net "M_B_CPU1_SA_DQ<6>")
	)
	(arc
		(start 89.947496 -273.777456)
		(mid 89.670937 -273.701713)
		(end 89.39276 -273.77136)
		(width 0.088646)
		(layer "In2.Cu")
		(net "M_B_CPU1_SA_DQ<6>")
	)
	(arc
		(start 87.502492 -273.777456)
		(mid 87.315294 -273.827599)
		(end 87.128096 -273.777456)
		(width 0.088646)
		(layer "In2.Cu")
		(net "M_B_CPU1_SA_DQ<6>")
	)
	(arc
		(start 89.00795 -273.777456)
		(mid 88.733751 -273.701621)
		(end 88.457278 -273.76882)
		(width 0.088646)
		(layer "In2.Cu")
		(net "M_B_CPU1_SA_DQ<6>")
	)
	(arc
		(start 86.086696 -274.594828)
		(mid 85.884109 -274.801179)
		(end 85.81009 -275.08073)
		(width 0.088646)
		(layer "In2.Cu")
		(net "M_B_CPU1_SA_DQ<6>")
	)
	(arc
		(start 85.81009 -275.08073)
		(mid 85.762411 -275.26363)
		(end 85.631528 -275.400008)
		(width 0.088646)
		(layer "In2.Cu")
		(net "M_B_CPU1_SA_DQ<6>")
	)
	(arc
		(start 88.442546 -273.777456)
		(mid 88.255348 -273.827599)
		(end 88.06815 -273.777456)
		(width 0.088646)
		(layer "In2.Cu")
		(net "M_B_CPU1_SA_DQ<6>")
	)
	(arc
		(start 85.34019 -275.8948)
		(mid 85.414181 -276.174366)
		(end 85.616796 -276.380702)
		(width 0.088646)
		(layer "In2.Cu")
		(net "M_B_CPU1_SA_DQ<6>")
	)
	(arc
		(start 85.622638 -275.405088)
		(mid 85.420352 -275.604069)
		(end 85.34019 -275.876258)
		(width 0.088646)
		(layer "In2.Cu")
		(net "M_B_CPU1_SA_DQ<6>")
	)
	(segment
		(start 41.3004 -308.2417)
		(end 41.29151 -308.23281)
		(width 0.1016)
		(layer "F.Cu")
		(net "M_B_CPU1_SA_DQ<5>")
	)
	(segment
		(start 40.682672 -308.23281)
		(end 40.520112 -308.39537)
		(width 0.20066)
		(layer "F.Cu")
		(net "M_B_CPU1_SA_DQ<5>")
	)
	(segment
		(start 41.29151 -308.23281)
		(end 40.682672 -308.23281)
		(width 0.20066)
		(layer "F.Cu")
		(net "M_B_CPU1_SA_DQ<5>")
	)
	(segment
		(start 43.795188 -308.2417)
		(end 43.616626 -308.2417)
		(width 0.20066)
		(layer "F.Cu")
		(net "M_B_CPU1_SA_DQ<5>")
	)
	(segment
		(start 40.520112 -308.39537)
		(end 40.520112 -308.723538)
		(width 0.20066)
		(layer "F.Cu")
		(net "M_B_CPU1_SA_DQ<5>")
	)
	(segment
		(start 39.649908 -308.666642)
		(end 38.315646 -308.666642)
		(width 0.20066)
		(layer "F.Cu")
		(net "M_B_CPU1_SA_DQ<5>")
	)
	(segment
		(start 39.861236 -308.87797)
		(end 39.649908 -308.666642)
		(width 0.20066)
		(layer "F.Cu")
		(net "M_B_CPU1_SA_DQ<5>")
	)
	(segment
		(start 40.36568 -308.87797)
		(end 39.861236 -308.87797)
		(width 0.20066)
		(layer "F.Cu")
		(net "M_B_CPU1_SA_DQ<5>")
	)
	(segment
		(start 43.285918 -308.2417)
		(end 41.3004 -308.2417)
		(width 0.1016)
		(layer "F.Cu")
		(net "M_B_CPU1_SA_DQ<5>")
	)
	(segment
		(start 43.616626 -308.2417)
		(end 43.285918 -308.2417)
		(width 0.101854)
		(layer "F.Cu")
		(net "M_B_CPU1_SA_DQ<5>")
	)
	(segment
		(start 40.520112 -308.723538)
		(end 40.36568 -308.87797)
		(width 0.20066)
		(layer "F.Cu")
		(net "M_B_CPU1_SA_DQ<5>")
	)
	(segment
		(start 44.22013 -308.666642)
		(end 43.795188 -308.2417)
		(width 0.20066)
		(layer "F.Cu")
		(net "M_B_CPU1_SA_DQ<5>")
	)
	(segment
		(start 45.859446 -308.666642)
		(end 44.22013 -308.666642)
		(width 0.20066)
		(layer "F.Cu")
		(net "M_B_CPU1_SA_DQ<5>")
	)
	(segment
		(start 89.194894 -272.917158)
		(end 89.194894 -273.453098)
		(width 0.20066)
		(layer "F.Cu")
		(net "M_B_CPU1_SA_DQ<5>")
	)
	(segment
		(start 46.964346 -308.666642)
		(end 45.859446 -308.666642)
		(width 0.20066)
		(layer "F.Cu")
		(net "M_B_CPU1_SA_DQ<5>")
	)
	(segment
		(start 80.429862 -284.470348)
		(end 77.61986 -287.28035)
		(width 0.18288)
		(layer "In2.Cu")
		(net "M_B_CPU1_SA_DQ<5>")
	)
	(segment
		(start 77.61986 -287.28035)
		(end 72.972168 -298.5008)
		(width 0.18288)
		(layer "In2.Cu")
		(net "M_B_CPU1_SA_DQ<5>")
	)
	(segment
		(start 58.393838 -307.401722)
		(end 56.346598 -307.401722)
		(width 0.18288)
		(layer "In2.Cu")
		(net "M_B_CPU1_SA_DQ<5>")
	)
	(segment
		(start 53.002942 -307.729382)
		(end 52.281074 -308.45125)
		(width 0.18288)
		(layer "In2.Cu")
		(net "M_B_CPU1_SA_DQ<5>")
	)
	(segment
		(start 81.507838 -281.867864)
		(end 81.183226 -282.651708)
		(width 0.18288)
		(layer "In2.Cu")
		(net "M_B_CPU1_SA_DQ<5>")
	)
	(segment
		(start 81.183226 -282.651708)
		(end 80.429862 -284.470348)
		(width 0.18288)
		(layer "In2.Cu")
		(net "M_B_CPU1_SA_DQ<5>")
	)
	(segment
		(start 53.998876 -307.633624)
		(end 53.998876 -307.89245)
		(width 0.18288)
		(layer "In2.Cu")
		(net "M_B_CPU1_SA_DQ<5>")
	)
	(segment
		(start 53.563012 -308.041548)
		(end 53.250846 -307.729382)
		(width 0.18288)
		(layer "In2.Cu")
		(net "M_B_CPU1_SA_DQ<5>")
	)
	(segment
		(start 89.390982 -273.13382)
		(end 89.382092 -273.12874)
		(width 0.088646)
		(layer "In2.Cu")
		(net "M_B_CPU1_SA_DQ<5>")
	)
	(segment
		(start 85.718396 -273.942556)
		(end 85.709506 -273.947636)
		(width 0.088646)
		(layer "In2.Cu")
		(net "M_B_CPU1_SA_DQ<5>")
	)
	(segment
		(start 48.345598 -308.030626)
		(end 48.345598 -307.79847)
		(width 0.18288)
		(layer "In2.Cu")
		(net "M_B_CPU1_SA_DQ<5>")
	)
	(segment
		(start 50.24755 -308.879494)
		(end 50.08753 -309.039514)
		(width 0.18288)
		(layer "In2.Cu")
		(net "M_B_CPU1_SA_DQ<5>")
	)
	(segment
		(start 85.724492 -273.939)
		(end 85.718396 -273.942556)
		(width 0.088646)
		(layer "In2.Cu")
		(net "M_B_CPU1_SA_DQ<5>")
	)
	(segment
		(start 67.35445 -308.233572)
		(end 64.22136 -308.233572)
		(width 0.18288)
		(layer "In2.Cu")
		(net "M_B_CPU1_SA_DQ<5>")
	)
	(segment
		(start 49.346612 -308.223666)
		(end 48.538638 -308.223666)
		(width 0.18288)
		(layer "In2.Cu")
		(net "M_B_CPU1_SA_DQ<5>")
	)
	(segment
		(start 64.22136 -308.233572)
		(end 64.11849 -308.130702)
		(width 0.18288)
		(layer "In2.Cu")
		(net "M_B_CPU1_SA_DQ<5>")
	)
	(segment
		(start 84.778342 -275.570442)
		(end 84.769452 -275.575522)
		(width 0.088646)
		(layer "In2.Cu")
		(net "M_B_CPU1_SA_DQ<5>")
	)
	(segment
		(start 81.507838 -280.730452)
		(end 81.507838 -281.867864)
		(width 0.18288)
		(layer "In2.Cu")
		(net "M_B_CPU1_SA_DQ<5>")
	)
	(segment
		(start 87.128096 -273.12874)
		(end 87.117682 -273.134836)
		(width 0.088646)
		(layer "In2.Cu")
		(net "M_B_CPU1_SA_DQ<5>")
	)
	(segment
		(start 54.372764 -307.259736)
		(end 53.998876 -307.633624)
		(width 0.18288)
		(layer "In2.Cu")
		(net "M_B_CPU1_SA_DQ<5>")
	)
	(segment
		(start 48.538638 -308.223666)
		(end 48.345598 -308.030626)
		(width 0.18288)
		(layer "In2.Cu")
		(net "M_B_CPU1_SA_DQ<5>")
	)
	(segment
		(start 62.809882 -308.820566)
		(end 62.098682 -308.820566)
		(width 0.18288)
		(layer "In2.Cu")
		(net "M_B_CPU1_SA_DQ<5>")
	)
	(segment
		(start 49.719484 -309.039514)
		(end 49.539652 -308.859682)
		(width 0.18288)
		(layer "In2.Cu")
		(net "M_B_CPU1_SA_DQ<5>")
	)
	(segment
		(start 89.007696 -273.12874)
		(end 88.992964 -273.137376)
		(width 0.088646)
		(layer "In2.Cu")
		(net "M_B_CPU1_SA_DQ<5>")
	)
	(segment
		(start 51.680872 -308.45125)
		(end 51.471322 -308.2417)
		(width 0.18288)
		(layer "In2.Cu")
		(net "M_B_CPU1_SA_DQ<5>")
	)
	(segment
		(start 48.152558 -307.60543)
		(end 47.715678 -307.60543)
		(width 0.18288)
		(layer "In2.Cu")
		(net "M_B_CPU1_SA_DQ<5>")
	)
	(segment
		(start 61.806836 -309.112412)
		(end 60.104528 -309.112412)
		(width 0.18288)
		(layer "In2.Cu")
		(net "M_B_CPU1_SA_DQ<5>")
	)
	(segment
		(start 88.067896 -273.12874)
		(end 88.053164 -273.137376)
		(width 0.088646)
		(layer "In2.Cu")
		(net "M_B_CPU1_SA_DQ<5>")
	)
	(segment
		(start 62.098682 -308.820566)
		(end 61.806836 -309.112412)
		(width 0.18288)
		(layer "In2.Cu")
		(net "M_B_CPU1_SA_DQ<5>")
	)
	(segment
		(start 85.061044 -276.708616)
		(end 85.061044 -276.72284)
		(width 0.088646)
		(layer "In2.Cu")
		(net "M_B_CPU1_SA_DQ<5>")
	)
	(segment
		(start 49.539652 -308.416706)
		(end 49.346612 -308.223666)
		(width 0.18288)
		(layer "In2.Cu")
		(net "M_B_CPU1_SA_DQ<5>")
	)
	(segment
		(start 85.248242 -274.756372)
		(end 85.239352 -274.761452)
		(width 0.088646)
		(layer "In2.Cu")
		(net "M_B_CPU1_SA_DQ<5>")
	)
	(segment
		(start 50.08753 -309.039514)
		(end 49.719484 -309.039514)
		(width 0.18288)
		(layer "In2.Cu")
		(net "M_B_CPU1_SA_DQ<5>")
	)
	(segment
		(start 49.539652 -308.859682)
		(end 49.539652 -308.416706)
		(width 0.18288)
		(layer "In2.Cu")
		(net "M_B_CPU1_SA_DQ<5>")
	)
	(segment
		(start 53.250846 -307.729382)
		(end 53.002942 -307.729382)
		(width 0.18288)
		(layer "In2.Cu")
		(net "M_B_CPU1_SA_DQ<5>")
	)
	(segment
		(start 71.123302 -304.46472)
		(end 67.35445 -308.233572)
		(width 0.18288)
		(layer "In2.Cu")
		(net "M_B_CPU1_SA_DQ<5>")
	)
	(segment
		(start 84.590128 -277.648162)
		(end 84.258658 -277.979632)
		(width 0.088646)
		(layer "In2.Cu")
		(net "M_B_CPU1_SA_DQ<5>")
	)
	(segment
		(start 85.06079 -275.08073)
		(end 85.06079 -275.099272)
		(width 0.088646)
		(layer "In2.Cu")
		(net "M_B_CPU1_SA_DQ<5>")
	)
	(segment
		(start 50.40757 -308.2417)
		(end 50.24755 -308.40172)
		(width 0.18288)
		(layer "In2.Cu")
		(net "M_B_CPU1_SA_DQ<5>")
	)
	(segment
		(start 50.24755 -308.40172)
		(end 50.24755 -308.879494)
		(width 0.18288)
		(layer "In2.Cu")
		(net "M_B_CPU1_SA_DQ<5>")
	)
	(segment
		(start 54.859682 -307.259736)
		(end 54.372764 -307.259736)
		(width 0.18288)
		(layer "In2.Cu")
		(net "M_B_CPU1_SA_DQ<5>")
	)
	(segment
		(start 89.507822 -273.453098)
		(end 89.564972 -273.395948)
		(width 0.088646)
		(layer "In2.Cu")
		(net "M_B_CPU1_SA_DQ<5>")
	)
	(segment
		(start 84.778342 -276.219158)
		(end 84.784438 -276.222714)
		(width 0.088646)
		(layer "In2.Cu")
		(net "M_B_CPU1_SA_DQ<5>")
	)
	(segment
		(start 72.972168 -298.5008)
		(end 72.397874 -301.388272)
		(width 0.18288)
		(layer "In2.Cu")
		(net "M_B_CPU1_SA_DQ<5>")
	)
	(segment
		(start 47.522638 -308.473602)
		(end 47.329598 -308.666642)
		(width 0.18288)
		(layer "In2.Cu")
		(net "M_B_CPU1_SA_DQ<5>")
	)
	(segment
		(start 84.778342 -277.198328)
		(end 84.769452 -277.203408)
		(width 0.088646)
		(layer "In2.Cu")
		(net "M_B_CPU1_SA_DQ<5>")
	)
	(segment
		(start 47.329598 -308.666642)
		(end 46.964346 -308.666642)
		(width 0.18288)
		(layer "In2.Cu")
		(net "M_B_CPU1_SA_DQ<5>")
	)
	(segment
		(start 85.254338 -274.752816)
		(end 85.251036 -274.754848)
		(width 0.088646)
		(layer "In2.Cu")
		(net "M_B_CPU1_SA_DQ<5>")
	)
	(segment
		(start 52.281074 -308.45125)
		(end 51.680872 -308.45125)
		(width 0.18288)
		(layer "In2.Cu")
		(net "M_B_CPU1_SA_DQ<5>")
	)
	(segment
		(start 53.849778 -308.041548)
		(end 53.563012 -308.041548)
		(width 0.18288)
		(layer "In2.Cu")
		(net "M_B_CPU1_SA_DQ<5>")
	)
	(segment
		(start 84.769452 -276.214078)
		(end 84.778342 -276.219158)
		(width 0.088646)
		(layer "In2.Cu")
		(net "M_B_CPU1_SA_DQ<5>")
	)
	(segment
		(start 55.261764 -307.661818)
		(end 54.859682 -307.259736)
		(width 0.18288)
		(layer "In2.Cu")
		(net "M_B_CPU1_SA_DQ<5>")
	)
	(segment
		(start 60.104528 -309.112412)
		(end 58.393838 -307.401722)
		(width 0.18288)
		(layer "In2.Cu")
		(net "M_B_CPU1_SA_DQ<5>")
	)
	(segment
		(start 63.499746 -308.130702)
		(end 62.809882 -308.820566)
		(width 0.18288)
		(layer "In2.Cu")
		(net "M_B_CPU1_SA_DQ<5>")
	)
	(segment
		(start 56.086502 -307.661818)
		(end 55.261764 -307.661818)
		(width 0.18288)
		(layer "In2.Cu")
		(net "M_B_CPU1_SA_DQ<5>")
	)
	(segment
		(start 51.471322 -308.2417)
		(end 50.40757 -308.2417)
		(width 0.18288)
		(layer "In2.Cu")
		(net "M_B_CPU1_SA_DQ<5>")
	)
	(segment
		(start 47.522638 -307.79847)
		(end 47.522638 -308.473602)
		(width 0.18288)
		(layer "In2.Cu")
		(net "M_B_CPU1_SA_DQ<5>")
	)
	(segment
		(start 84.258658 -277.979632)
		(end 81.507838 -280.730452)
		(width 0.18288)
		(layer "In2.Cu")
		(net "M_B_CPU1_SA_DQ<5>")
	)
	(segment
		(start 64.11849 -308.130702)
		(end 63.499746 -308.130702)
		(width 0.18288)
		(layer "In2.Cu")
		(net "M_B_CPU1_SA_DQ<5>")
	)
	(segment
		(start 84.700364 -277.25751)
		(end 84.589874 -277.368)
		(width 0.088646)
		(layer "In2.Cu")
		(net "M_B_CPU1_SA_DQ<5>")
	)
	(segment
		(start 84.589874 -277.368)
		(end 84.589874 -277.52294)
		(width 0.088646)
		(layer "In2.Cu")
		(net "M_B_CPU1_SA_DQ<5>")
	)
	(segment
		(start 47.715678 -307.60543)
		(end 47.522638 -307.79847)
		(width 0.18288)
		(layer "In2.Cu")
		(net "M_B_CPU1_SA_DQ<5>")
	)
	(segment
		(start 53.998876 -307.89245)
		(end 53.849778 -308.041548)
		(width 0.18288)
		(layer "In2.Cu")
		(net "M_B_CPU1_SA_DQ<5>")
	)
	(segment
		(start 89.194894 -273.453098)
		(end 89.507822 -273.453098)
		(width 0.088646)
		(layer "In2.Cu")
		(net "M_B_CPU1_SA_DQ<5>")
	)
	(segment
		(start 56.346598 -307.401722)
		(end 56.086502 -307.661818)
		(width 0.18288)
		(layer "In2.Cu")
		(net "M_B_CPU1_SA_DQ<5>")
	)
	(segment
		(start 86.18855 -273.12874)
		(end 86.17966 -273.13382)
		(width 0.088646)
		(layer "In2.Cu")
		(net "M_B_CPU1_SA_DQ<5>")
	)
	(segment
		(start 85.251036 -274.754848)
		(end 85.248242 -274.756372)
		(width 0.088646)
		(layer "In2.Cu")
		(net "M_B_CPU1_SA_DQ<5>")
	)
	(segment
		(start 84.589874 -277.52294)
		(end 84.590128 -277.648162)
		(width 0.088646)
		(layer "In2.Cu")
		(net "M_B_CPU1_SA_DQ<5>")
	)
	(segment
		(start 72.397874 -301.388272)
		(end 71.123302 -304.46472)
		(width 0.18288)
		(layer "In2.Cu")
		(net "M_B_CPU1_SA_DQ<5>")
	)
	(segment
		(start 48.345598 -307.79847)
		(end 48.152558 -307.60543)
		(width 0.18288)
		(layer "In2.Cu")
		(net "M_B_CPU1_SA_DQ<5>")
	)
	(arc
		(start 88.442292 -273.12874)
		(mid 88.255094 -273.078597)
		(end 88.067896 -273.12874)
		(width 0.088646)
		(layer "In2.Cu")
		(net "M_B_CPU1_SA_DQ<5>")
	)
	(arc
		(start 88.053164 -273.137376)
		(mid 87.776689 -273.204696)
		(end 87.502492 -273.12874)
		(width 0.088646)
		(layer "In2.Cu")
		(net "M_B_CPU1_SA_DQ<5>")
	)
	(arc
		(start 86.001098 -273.453098)
		(mid 85.927107 -273.732664)
		(end 85.724492 -273.939)
		(width 0.088646)
		(layer "In2.Cu")
		(net "M_B_CPU1_SA_DQ<5>")
	)
	(arc
		(start 87.502492 -273.12874)
		(mid 87.315294 -273.078597)
		(end 87.128096 -273.12874)
		(width 0.088646)
		(layer "In2.Cu")
		(net "M_B_CPU1_SA_DQ<5>")
	)
	(arc
		(start 84.769452 -277.203408)
		(mid 84.733314 -277.228424)
		(end 84.700364 -277.25751)
		(width 0.088646)
		(layer "In2.Cu")
		(net "M_B_CPU1_SA_DQ<5>")
	)
	(arc
		(start 85.530944 -274.266914)
		(mid 85.456953 -274.54648)
		(end 85.254338 -274.752816)
		(width 0.088646)
		(layer "In2.Cu")
		(net "M_B_CPU1_SA_DQ<5>")
	)
	(arc
		(start 88.992964 -273.137376)
		(mid 88.716489 -273.204696)
		(end 88.442292 -273.12874)
		(width 0.088646)
		(layer "In2.Cu")
		(net "M_B_CPU1_SA_DQ<5>")
	)
	(arc
		(start 86.562946 -273.12874)
		(mid 86.375748 -273.078597)
		(end 86.18855 -273.12874)
		(width 0.088646)
		(layer "In2.Cu")
		(net "M_B_CPU1_SA_DQ<5>")
	)
	(arc
		(start 84.769452 -275.575522)
		(mid 84.590855 -275.8948)
		(end 84.769452 -276.214078)
		(width 0.088646)
		(layer "In2.Cu")
		(net "M_B_CPU1_SA_DQ<5>")
	)
	(arc
		(start 86.17966 -273.13382)
		(mid 86.048746 -273.27018)
		(end 86.001098 -273.453098)
		(width 0.088646)
		(layer "In2.Cu")
		(net "M_B_CPU1_SA_DQ<5>")
	)
	(arc
		(start 85.239352 -274.761452)
		(mid 85.108438 -274.897812)
		(end 85.06079 -275.08073)
		(width 0.088646)
		(layer "In2.Cu")
		(net "M_B_CPU1_SA_DQ<5>")
	)
	(arc
		(start 84.784438 -276.222714)
		(mid 84.987025 -276.429065)
		(end 85.061044 -276.708616)
		(width 0.088646)
		(layer "In2.Cu")
		(net "M_B_CPU1_SA_DQ<5>")
	)
	(arc
		(start 89.564972 -273.395948)
		(mid 89.506853 -273.245707)
		(end 89.390982 -273.13382)
		(width 0.088646)
		(layer "In2.Cu")
		(net "M_B_CPU1_SA_DQ<5>")
	)
	(arc
		(start 85.709506 -273.947636)
		(mid 85.578592 -274.083996)
		(end 85.530944 -274.266914)
		(width 0.088646)
		(layer "In2.Cu")
		(net "M_B_CPU1_SA_DQ<5>")
	)
	(arc
		(start 87.117682 -273.134836)
		(mid 86.839504 -273.204559)
		(end 86.562946 -273.12874)
		(width 0.088646)
		(layer "In2.Cu")
		(net "M_B_CPU1_SA_DQ<5>")
	)
	(arc
		(start 85.06079 -275.099272)
		(mid 84.980628 -275.371461)
		(end 84.778342 -275.570442)
		(width 0.088646)
		(layer "In2.Cu")
		(net "M_B_CPU1_SA_DQ<5>")
	)
	(arc
		(start 89.382092 -273.12874)
		(mid 89.194894 -273.078597)
		(end 89.007696 -273.12874)
		(width 0.088646)
		(layer "In2.Cu")
		(net "M_B_CPU1_SA_DQ<5>")
	)
	(arc
		(start 85.061044 -276.72284)
		(mid 84.981825 -276.997525)
		(end 84.778342 -277.198328)
		(width 0.088646)
		(layer "In2.Cu")
		(net "M_B_CPU1_SA_DQ<5>")
	)
	(segment
		(start 43.616626 -309.941722)
		(end 41.547542 -309.941722)
		(width 0.1016)
		(layer "F.Cu")
		(net "M_B_CPU1_SA_DQ<4>")
	)
	(segment
		(start 40.520112 -310.432704)
		(end 40.347392 -310.605424)
		(width 0.20066)
		(layer "F.Cu")
		(net "M_B_CPU1_SA_DQ<4>")
	)
	(segment
		(start 41.29151 -309.933594)
		(end 40.729662 -309.933594)
		(width 0.20066)
		(layer "F.Cu")
		(net "M_B_CPU1_SA_DQ<4>")
	)
	(segment
		(start 88.725248 -273.730974)
		(end 88.725248 -274.26666)
		(width 0.20066)
		(layer "F.Cu")
		(net "M_B_CPU1_SA_DQ<4>")
	)
	(segment
		(start 40.347392 -310.605424)
		(end 39.888668 -310.605424)
		(width 0.20066)
		(layer "F.Cu")
		(net "M_B_CPU1_SA_DQ<4>")
	)
	(segment
		(start 44.065444 -309.941722)
		(end 43.616626 -309.941722)
		(width 0.20066)
		(layer "F.Cu")
		(net "M_B_CPU1_SA_DQ<4>")
	)
	(segment
		(start 88.725248 -274.26666)
		(end 88.724994 -274.266914)
		(width 0.20066)
		(layer "F.Cu")
		(net "M_B_CPU1_SA_DQ<4>")
	)
	(segment
		(start 40.729662 -309.933594)
		(end 40.520112 -310.143144)
		(width 0.20066)
		(layer "F.Cu")
		(net "M_B_CPU1_SA_DQ<4>")
	)
	(segment
		(start 41.299638 -309.941722)
		(end 41.29151 -309.933594)
		(width 0.101854)
		(layer "F.Cu")
		(net "M_B_CPU1_SA_DQ<4>")
	)
	(segment
		(start 39.649908 -310.366664)
		(end 38.315646 -310.366664)
		(width 0.20066)
		(layer "F.Cu")
		(net "M_B_CPU1_SA_DQ<4>")
	)
	(segment
		(start 40.520112 -310.143144)
		(end 40.520112 -310.432704)
		(width 0.20066)
		(layer "F.Cu")
		(net "M_B_CPU1_SA_DQ<4>")
	)
	(segment
		(start 46.964346 -310.366664)
		(end 45.859446 -310.366664)
		(width 0.20066)
		(layer "F.Cu")
		(net "M_B_CPU1_SA_DQ<4>")
	)
	(segment
		(start 41.547542 -309.941722)
		(end 41.299638 -309.941722)
		(width 0.101854)
		(layer "F.Cu")
		(net "M_B_CPU1_SA_DQ<4>")
	)
	(segment
		(start 44.490386 -310.366664)
		(end 44.065444 -309.941722)
		(width 0.20066)
		(layer "F.Cu")
		(net "M_B_CPU1_SA_DQ<4>")
	)
	(segment
		(start 39.888668 -310.605424)
		(end 39.649908 -310.366664)
		(width 0.20066)
		(layer "F.Cu")
		(net "M_B_CPU1_SA_DQ<4>")
	)
	(segment
		(start 45.859446 -310.366664)
		(end 44.490386 -310.366664)
		(width 0.20066)
		(layer "F.Cu")
		(net "M_B_CPU1_SA_DQ<4>")
	)
	(segment
		(start 63.557912 -309.799736)
		(end 62.615318 -310.74233)
		(width 0.18288)
		(layer "In2.Cu")
		(net "M_B_CPU1_SA_DQ<4>")
	)
	(segment
		(start 62.615318 -310.74233)
		(end 59.10961 -310.74233)
		(width 0.18288)
		(layer "In2.Cu")
		(net "M_B_CPU1_SA_DQ<4>")
	)
	(segment
		(start 85.53069 -277.511256)
		(end 85.53069 -277.697438)
		(width 0.088646)
		(layer "In2.Cu")
		(net "M_B_CPU1_SA_DQ<4>")
	)
	(segment
		(start 51.14671 -310.789574)
		(end 51.144678 -310.791606)
		(width 0.18288)
		(layer "In2.Cu")
		(net "M_B_CPU1_SA_DQ<4>")
	)
	(segment
		(start 47.716948 -309.47233)
		(end 47.580296 -309.608982)
		(width 0.18288)
		(layer "In2.Cu")
		(net "M_B_CPU1_SA_DQ<4>")
	)
	(segment
		(start 47.443644 -310.366664)
		(end 46.964346 -310.366664)
		(width 0.18288)
		(layer "In2.Cu")
		(net "M_B_CPU1_SA_DQ<4>")
	)
	(segment
		(start 48.487838 -310.811926)
		(end 48.325278 -310.649366)
		(width 0.18288)
		(layer "In2.Cu")
		(net "M_B_CPU1_SA_DQ<4>")
	)
	(segment
		(start 85.718142 -276.219158)
		(end 85.724238 -276.222714)
		(width 0.088646)
		(layer "In2.Cu")
		(net "M_B_CPU1_SA_DQ<4>")
	)
	(segment
		(start 49.619916 -310.0197)
		(end 49.459896 -310.17972)
		(width 0.18288)
		(layer "In2.Cu")
		(net "M_B_CPU1_SA_DQ<4>")
	)
	(segment
		(start 84.753704 -278.474424)
		(end 82.198718 -281.02941)
		(width 0.18288)
		(layer "In2.Cu")
		(net "M_B_CPU1_SA_DQ<4>")
	)
	(segment
		(start 86.00059 -275.08073)
		(end 86.00059 -275.099272)
		(width 0.088646)
		(layer "In2.Cu")
		(net "M_B_CPU1_SA_DQ<4>")
	)
	(segment
		(start 73.371202 -301.703232)
		(end 71.990204 -305.036982)
		(width 0.18288)
		(layer "In2.Cu")
		(net "M_B_CPU1_SA_DQ<4>")
	)
	(segment
		(start 82.198718 -281.02941)
		(end 82.198718 -282.855924)
		(width 0.18288)
		(layer "In2.Cu")
		(net "M_B_CPU1_SA_DQ<4>")
	)
	(segment
		(start 56.486298 -311.00395)
		(end 55.236618 -311.00395)
		(width 0.18288)
		(layer "In2.Cu")
		(net "M_B_CPU1_SA_DQ<4>")
	)
	(segment
		(start 67.135756 -309.89143)
		(end 64.198754 -309.89143)
		(width 0.18288)
		(layer "In2.Cu")
		(net "M_B_CPU1_SA_DQ<4>")
	)
	(segment
		(start 48.325278 -309.66537)
		(end 48.132238 -309.47233)
		(width 0.18288)
		(layer "In2.Cu")
		(net "M_B_CPU1_SA_DQ<4>")
	)
	(segment
		(start 51.71186 -310.789574)
		(end 51.14671 -310.789574)
		(width 0.18288)
		(layer "In2.Cu")
		(net "M_B_CPU1_SA_DQ<4>")
	)
	(segment
		(start 86.000844 -276.708616)
		(end 86.000844 -276.72284)
		(width 0.088646)
		(layer "In2.Cu")
		(net "M_B_CPU1_SA_DQ<4>")
	)
	(segment
		(start 48.325278 -310.649366)
		(end 48.325278 -309.66537)
		(width 0.18288)
		(layer "In2.Cu")
		(net "M_B_CPU1_SA_DQ<4>")
	)
	(segment
		(start 57.394856 -310.095392)
		(end 56.486298 -311.00395)
		(width 0.18288)
		(layer "In2.Cu")
		(net "M_B_CPU1_SA_DQ<4>")
	)
	(segment
		(start 86.190836 -274.754848)
		(end 86.188042 -274.756372)
		(width 0.088646)
		(layer "In2.Cu")
		(net "M_B_CPU1_SA_DQ<4>")
	)
	(segment
		(start 47.580296 -309.608982)
		(end 47.580296 -310.230012)
		(width 0.18288)
		(layer "In2.Cu")
		(net "M_B_CPU1_SA_DQ<4>")
	)
	(segment
		(start 49.459896 -310.17972)
		(end 49.459896 -310.630824)
		(width 0.18288)
		(layer "In2.Cu")
		(net "M_B_CPU1_SA_DQ<4>")
	)
	(segment
		(start 49.278794 -310.811926)
		(end 48.487838 -310.811926)
		(width 0.18288)
		(layer "In2.Cu")
		(net "M_B_CPU1_SA_DQ<4>")
	)
	(segment
		(start 54.185058 -309.95239)
		(end 52.549044 -309.95239)
		(width 0.18288)
		(layer "In2.Cu")
		(net "M_B_CPU1_SA_DQ<4>")
	)
	(segment
		(start 73.938892 -298.849796)
		(end 73.371202 -301.703232)
		(width 0.18288)
		(layer "In2.Cu")
		(net "M_B_CPU1_SA_DQ<4>")
	)
	(segment
		(start 86.194138 -274.752816)
		(end 86.190836 -274.754848)
		(width 0.088646)
		(layer "In2.Cu")
		(net "M_B_CPU1_SA_DQ<4>")
	)
	(segment
		(start 89.037922 -274.266914)
		(end 89.095072 -274.209764)
		(width 0.088646)
		(layer "In2.Cu")
		(net "M_B_CPU1_SA_DQ<4>")
	)
	(segment
		(start 78.490826 -287.86074)
		(end 73.938892 -298.849796)
		(width 0.18288)
		(layer "In2.Cu")
		(net "M_B_CPU1_SA_DQ<4>")
	)
	(segment
		(start 47.580296 -310.230012)
		(end 47.443644 -310.366664)
		(width 0.18288)
		(layer "In2.Cu")
		(net "M_B_CPU1_SA_DQ<4>")
	)
	(segment
		(start 58.885074 -310.966866)
		(end 58.539634 -310.966866)
		(width 0.18288)
		(layer "In2.Cu")
		(net "M_B_CPU1_SA_DQ<4>")
	)
	(segment
		(start 51.144678 -310.791606)
		(end 50.368708 -310.791606)
		(width 0.18288)
		(layer "In2.Cu")
		(net "M_B_CPU1_SA_DQ<4>")
	)
	(segment
		(start 82.198718 -282.855924)
		(end 81.41081 -284.75813)
		(width 0.18288)
		(layer "In2.Cu")
		(net "M_B_CPU1_SA_DQ<4>")
	)
	(segment
		(start 81.281524 -285.070042)
		(end 78.490826 -287.86074)
		(width 0.18288)
		(layer "In2.Cu")
		(net "M_B_CPU1_SA_DQ<4>")
	)
	(segment
		(start 81.41081 -284.75813)
		(end 81.281524 -285.070042)
		(width 0.18288)
		(layer "In2.Cu")
		(net "M_B_CPU1_SA_DQ<4>")
	)
	(segment
		(start 50.368708 -310.791606)
		(end 50.207926 -310.630824)
		(width 0.18288)
		(layer "In2.Cu")
		(net "M_B_CPU1_SA_DQ<4>")
	)
	(segment
		(start 50.207926 -310.17972)
		(end 50.047906 -310.0197)
		(width 0.18288)
		(layer "In2.Cu")
		(net "M_B_CPU1_SA_DQ<4>")
	)
	(segment
		(start 86.188042 -274.756372)
		(end 86.179152 -274.761452)
		(width 0.088646)
		(layer "In2.Cu")
		(net "M_B_CPU1_SA_DQ<4>")
	)
	(segment
		(start 86.658196 -273.942556)
		(end 86.649306 -273.947636)
		(width 0.088646)
		(layer "In2.Cu")
		(net "M_B_CPU1_SA_DQ<4>")
	)
	(segment
		(start 64.198754 -309.89143)
		(end 64.10706 -309.799736)
		(width 0.18288)
		(layer "In2.Cu")
		(net "M_B_CPU1_SA_DQ<4>")
	)
	(segment
		(start 85.53069 -277.697438)
		(end 84.753704 -278.474424)
		(width 0.088646)
		(layer "In2.Cu")
		(net "M_B_CPU1_SA_DQ<4>")
	)
	(segment
		(start 52.549044 -309.95239)
		(end 51.71186 -310.789574)
		(width 0.18288)
		(layer "In2.Cu")
		(net "M_B_CPU1_SA_DQ<4>")
	)
	(segment
		(start 88.921082 -273.947636)
		(end 88.912192 -273.942556)
		(width 0.088646)
		(layer "In2.Cu")
		(net "M_B_CPU1_SA_DQ<4>")
	)
	(segment
		(start 48.132238 -309.47233)
		(end 47.716948 -309.47233)
		(width 0.18288)
		(layer "In2.Cu")
		(net "M_B_CPU1_SA_DQ<4>")
	)
	(segment
		(start 85.709252 -276.214078)
		(end 85.718142 -276.219158)
		(width 0.088646)
		(layer "In2.Cu")
		(net "M_B_CPU1_SA_DQ<4>")
	)
	(segment
		(start 57.66816 -310.095392)
		(end 57.394856 -310.095392)
		(width 0.18288)
		(layer "In2.Cu")
		(net "M_B_CPU1_SA_DQ<4>")
	)
	(segment
		(start 55.236618 -311.00395)
		(end 54.185058 -309.95239)
		(width 0.18288)
		(layer "In2.Cu")
		(net "M_B_CPU1_SA_DQ<4>")
	)
	(segment
		(start 85.718142 -277.198328)
		(end 85.709252 -277.203408)
		(width 0.088646)
		(layer "In2.Cu")
		(net "M_B_CPU1_SA_DQ<4>")
	)
	(segment
		(start 50.207926 -310.630824)
		(end 50.207926 -310.17972)
		(width 0.18288)
		(layer "In2.Cu")
		(net "M_B_CPU1_SA_DQ<4>")
	)
	(segment
		(start 49.459896 -310.630824)
		(end 49.278794 -310.811926)
		(width 0.18288)
		(layer "In2.Cu")
		(net "M_B_CPU1_SA_DQ<4>")
	)
	(segment
		(start 71.990204 -305.036982)
		(end 67.135756 -309.89143)
		(width 0.18288)
		(layer "In2.Cu")
		(net "M_B_CPU1_SA_DQ<4>")
	)
	(segment
		(start 88.724994 -274.266914)
		(end 89.037922 -274.266914)
		(width 0.088646)
		(layer "In2.Cu")
		(net "M_B_CPU1_SA_DQ<4>")
	)
	(segment
		(start 50.047906 -310.0197)
		(end 49.619916 -310.0197)
		(width 0.18288)
		(layer "In2.Cu")
		(net "M_B_CPU1_SA_DQ<4>")
	)
	(segment
		(start 85.718142 -275.570442)
		(end 85.709252 -275.575522)
		(width 0.088646)
		(layer "In2.Cu")
		(net "M_B_CPU1_SA_DQ<4>")
	)
	(segment
		(start 59.10961 -310.74233)
		(end 58.885074 -310.966866)
		(width 0.18288)
		(layer "In2.Cu")
		(net "M_B_CPU1_SA_DQ<4>")
	)
	(segment
		(start 64.10706 -309.799736)
		(end 63.557912 -309.799736)
		(width 0.18288)
		(layer "In2.Cu")
		(net "M_B_CPU1_SA_DQ<4>")
	)
	(segment
		(start 58.539634 -310.966866)
		(end 57.66816 -310.095392)
		(width 0.18288)
		(layer "In2.Cu")
		(net "M_B_CPU1_SA_DQ<4>")
	)
	(arc
		(start 87.972392 -273.942556)
		(mid 87.785194 -273.892413)
		(end 87.597996 -273.942556)
		(width 0.088646)
		(layer "In2.Cu")
		(net "M_B_CPU1_SA_DQ<4>")
	)
	(arc
		(start 88.912192 -273.942556)
		(mid 88.724994 -273.892413)
		(end 88.537796 -273.942556)
		(width 0.088646)
		(layer "In2.Cu")
		(net "M_B_CPU1_SA_DQ<4>")
	)
	(arc
		(start 85.724238 -276.222714)
		(mid 85.926825 -276.429065)
		(end 86.000844 -276.708616)
		(width 0.088646)
		(layer "In2.Cu")
		(net "M_B_CPU1_SA_DQ<4>")
	)
	(arc
		(start 89.095072 -274.209764)
		(mid 89.036953 -274.059523)
		(end 88.921082 -273.947636)
		(width 0.088646)
		(layer "In2.Cu")
		(net "M_B_CPU1_SA_DQ<4>")
	)
	(arc
		(start 87.597996 -273.942556)
		(mid 87.315294 -274.018332)
		(end 87.032592 -273.942556)
		(width 0.088646)
		(layer "In2.Cu")
		(net "M_B_CPU1_SA_DQ<4>")
	)
	(arc
		(start 85.709252 -275.575522)
		(mid 85.530655 -275.8948)
		(end 85.709252 -276.214078)
		(width 0.088646)
		(layer "In2.Cu")
		(net "M_B_CPU1_SA_DQ<4>")
	)
	(arc
		(start 86.000844 -276.72284)
		(mid 85.921625 -276.997525)
		(end 85.718142 -277.198328)
		(width 0.088646)
		(layer "In2.Cu")
		(net "M_B_CPU1_SA_DQ<4>")
	)
	(arc
		(start 85.709252 -277.203408)
		(mid 85.581075 -277.334781)
		(end 85.53069 -277.511256)
		(width 0.088646)
		(layer "In2.Cu")
		(net "M_B_CPU1_SA_DQ<4>")
	)
	(arc
		(start 86.179152 -274.761452)
		(mid 86.048238 -274.897812)
		(end 86.00059 -275.08073)
		(width 0.088646)
		(layer "In2.Cu")
		(net "M_B_CPU1_SA_DQ<4>")
	)
	(arc
		(start 86.470744 -274.266914)
		(mid 86.396753 -274.54648)
		(end 86.194138 -274.752816)
		(width 0.088646)
		(layer "In2.Cu")
		(net "M_B_CPU1_SA_DQ<4>")
	)
	(arc
		(start 86.649306 -273.947636)
		(mid 86.518392 -274.083996)
		(end 86.470744 -274.266914)
		(width 0.088646)
		(layer "In2.Cu")
		(net "M_B_CPU1_SA_DQ<4>")
	)
	(arc
		(start 87.032592 -273.942556)
		(mid 86.845394 -273.892413)
		(end 86.658196 -273.942556)
		(width 0.088646)
		(layer "In2.Cu")
		(net "M_B_CPU1_SA_DQ<4>")
	)
	(arc
		(start 88.537796 -273.942556)
		(mid 88.255094 -274.018332)
		(end 87.972392 -273.942556)
		(width 0.088646)
		(layer "In2.Cu")
		(net "M_B_CPU1_SA_DQ<4>")
	)
	(arc
		(start 86.00059 -275.099272)
		(mid 85.920428 -275.371461)
		(end 85.718142 -275.570442)
		(width 0.088646)
		(layer "In2.Cu")
		(net "M_B_CPU1_SA_DQ<4>")
	)
	(segment
		(start 44.112942 -313.766708)
		(end 42.415714 -313.766708)
		(width 0.20066)
		(layer "F.Cu")
		(net "M_B_CPU1_SA_DQ<3>")
	)
	(segment
		(start 44.987464 -314.19165)
		(end 44.749466 -314.19165)
		(width 0.101854)
		(layer "F.Cu")
		(net "M_B_CPU1_SA_DQ<3>")
	)
	(segment
		(start 44.238926 -313.892692)
		(end 44.112942 -313.766708)
		(width 0.20066)
		(layer "F.Cu")
		(net "M_B_CPU1_SA_DQ<3>")
	)
	(segment
		(start 44.735242 -314.205874)
		(end 44.38142 -314.205874)
		(width 0.20066)
		(layer "F.Cu")
		(net "M_B_CPU1_SA_DQ<3>")
	)
	(segment
		(start 44.38142 -314.205874)
		(end 44.238926 -314.06338)
		(width 0.20066)
		(layer "F.Cu")
		(net "M_B_CPU1_SA_DQ<3>")
	)
	(segment
		(start 47.882302 -313.76239)
		(end 47.753778 -313.890914)
		(width 0.20066)
		(layer "F.Cu")
		(net "M_B_CPU1_SA_DQ<3>")
	)
	(segment
		(start 49.959514 -313.766708)
		(end 49.143412 -313.766708)
		(width 0.20066)
		(layer "F.Cu")
		(net "M_B_CPU1_SA_DQ<3>")
	)
	(segment
		(start 47.060358 -314.19165)
		(end 44.987464 -314.19165)
		(width 0.1016)
		(layer "F.Cu")
		(net "M_B_CPU1_SA_DQ<3>")
	)
	(segment
		(start 90.604848 -275.35886)
		(end 90.604848 -275.894292)
		(width 0.20066)
		(layer "F.Cu")
		(net "M_B_CPU1_SA_DQ<3>")
	)
	(segment
		(start 51.089814 -313.766708)
		(end 49.959514 -313.766708)
		(width 0.20066)
		(layer "F.Cu")
		(net "M_B_CPU1_SA_DQ<3>")
	)
	(segment
		(start 48.935894 -313.974226)
		(end 48.489362 -313.974226)
		(width 0.20066)
		(layer "F.Cu")
		(net "M_B_CPU1_SA_DQ<3>")
	)
	(segment
		(start 47.753778 -313.890914)
		(end 47.753778 -314.042552)
		(width 0.20066)
		(layer "F.Cu")
		(net "M_B_CPU1_SA_DQ<3>")
	)
	(segment
		(start 44.749466 -314.19165)
		(end 44.735242 -314.205874)
		(width 0.101854)
		(layer "F.Cu")
		(net "M_B_CPU1_SA_DQ<3>")
	)
	(segment
		(start 48.277526 -313.76239)
		(end 47.882302 -313.76239)
		(width 0.20066)
		(layer "F.Cu")
		(net "M_B_CPU1_SA_DQ<3>")
	)
	(segment
		(start 47.60468 -314.19165)
		(end 47.060358 -314.19165)
		(width 0.20066)
		(layer "F.Cu")
		(net "M_B_CPU1_SA_DQ<3>")
	)
	(segment
		(start 44.238926 -314.06338)
		(end 44.238926 -313.892692)
		(width 0.20066)
		(layer "F.Cu")
		(net "M_B_CPU1_SA_DQ<3>")
	)
	(segment
		(start 49.143412 -313.766708)
		(end 48.935894 -313.974226)
		(width 0.20066)
		(layer "F.Cu")
		(net "M_B_CPU1_SA_DQ<3>")
	)
	(segment
		(start 47.753778 -314.042552)
		(end 47.60468 -314.19165)
		(width 0.20066)
		(layer "F.Cu")
		(net "M_B_CPU1_SA_DQ<3>")
	)
	(segment
		(start 48.489362 -313.974226)
		(end 48.277526 -313.76239)
		(width 0.20066)
		(layer "F.Cu")
		(net "M_B_CPU1_SA_DQ<3>")
	)
	(arc
		(start 90.604848 -275.894292)
		(mid 90.60479 -275.894584)
		(end 90.604594 -275.8948)
		(width 0.20066)
		(layer "F.Cu")
		(net "M_B_CPU1_SA_DQ<3>")
	)
	(segment
		(start 65.137538 -314.533534)
		(end 64.794384 -314.533534)
		(width 0.18288)
		(layer "In2.Cu")
		(net "M_B_CPU1_SA_DQ<3>")
	)
	(segment
		(start 59.249564 -315.29655)
		(end 58.595514 -315.29655)
		(width 0.18288)
		(layer "In2.Cu")
		(net "M_B_CPU1_SA_DQ<3>")
	)
	(segment
		(start 75.860402 -300.287182)
		(end 75.236832 -303.422304)
		(width 0.18288)
		(layer "In2.Cu")
		(net "M_B_CPU1_SA_DQ<3>")
	)
	(segment
		(start 55.742078 -315.019182)
		(end 55.742078 -314.553346)
		(width 0.18288)
		(layer "In2.Cu")
		(net "M_B_CPU1_SA_DQ<3>")
	)
	(segment
		(start 63.120016 -313.81954)
		(end 62.84722 -313.81954)
		(width 0.18288)
		(layer "In2.Cu")
		(net "M_B_CPU1_SA_DQ<3>")
	)
	(segment
		(start 62.204092 -314.928758)
		(end 61.931296 -314.928758)
		(width 0.18288)
		(layer "In2.Cu")
		(net "M_B_CPU1_SA_DQ<3>")
	)
	(segment
		(start 60.173362 -314.9854)
		(end 59.560714 -314.9854)
		(width 0.18288)
		(layer "In2.Cu")
		(net "M_B_CPU1_SA_DQ<3>")
	)
	(segment
		(start 88.911938 -277.198328)
		(end 88.920828 -277.203408)
		(width 0.088646)
		(layer "In2.Cu")
		(net "M_B_CPU1_SA_DQ<3>")
	)
	(segment
		(start 55.549038 -314.360306)
		(end 55.231538 -314.360306)
		(width 0.18288)
		(layer "In2.Cu")
		(net "M_B_CPU1_SA_DQ<3>")
	)
	(segment
		(start 88.350344 -275.8948)
		(end 88.350344 -276.065488)
		(width 0.088646)
		(layer "In2.Cu")
		(net "M_B_CPU1_SA_DQ<3>")
	)
	(segment
		(start 88.537796 -275.570442)
		(end 88.537796 -275.570696)
		(width 0.088646)
		(layer "In2.Cu")
		(net "M_B_CPU1_SA_DQ<3>")
	)
	(segment
		(start 84.98205 -281.141678)
		(end 83.875118 -282.24861)
		(width 0.18288)
		(layer "In2.Cu")
		(net "M_B_CPU1_SA_DQ<3>")
	)
	(segment
		(start 86.280244 -280.759662)
		(end 86.280244 -280.778204)
		(width 0.088646)
		(layer "In2.Cu")
		(net "M_B_CPU1_SA_DQ<3>")
	)
	(segment
		(start 75.236832 -303.422304)
		(end 74.047604 -306.293012)
		(width 0.18288)
		(layer "In2.Cu")
		(net "M_B_CPU1_SA_DQ<3>")
	)
	(segment
		(start 58.387234 -315.08827)
		(end 56.677052 -315.08827)
		(width 0.18288)
		(layer "In2.Cu")
		(net "M_B_CPU1_SA_DQ<3>")
	)
	(segment
		(start 56.518302 -315.24702)
		(end 55.969916 -315.24702)
		(width 0.18288)
		(layer "In2.Cu")
		(net "M_B_CPU1_SA_DQ<3>")
	)
	(segment
		(start 66.839338 -313.501278)
		(end 66.167508 -314.173108)
		(width 0.18288)
		(layer "In2.Cu")
		(net "M_B_CPU1_SA_DQ<3>")
	)
	(segment
		(start 83.875118 -284.488128)
		(end 83.710272 -284.886146)
		(width 0.18288)
		(layer "In2.Cu")
		(net "M_B_CPU1_SA_DQ<3>")
	)
	(segment
		(start 88.628982 -278.336756)
		(end 88.62822 -278.336756)
		(width 0.088646)
		(layer "In2.Cu")
		(net "M_B_CPU1_SA_DQ<3>")
	)
	(segment
		(start 55.742078 -314.553346)
		(end 55.549038 -314.360306)
		(width 0.18288)
		(layer "In2.Cu")
		(net "M_B_CPU1_SA_DQ<3>")
	)
	(segment
		(start 54.921658 -315.020198)
		(end 54.496208 -315.020198)
		(width 0.18288)
		(layer "In2.Cu")
		(net "M_B_CPU1_SA_DQ<3>")
	)
	(segment
		(start 88.159844 -279.140412)
		(end 88.159844 -279.150318)
		(width 0.088646)
		(layer "In2.Cu")
		(net "M_B_CPU1_SA_DQ<3>")
	)
	(segment
		(start 83.875118 -282.24861)
		(end 83.875118 -284.488128)
		(width 0.18288)
		(layer "In2.Cu")
		(net "M_B_CPU1_SA_DQ<3>")
	)
	(segment
		(start 88.62822 -278.336756)
		(end 88.62822 -278.34463)
		(width 0.088646)
		(layer "In2.Cu")
		(net "M_B_CPU1_SA_DQ<3>")
	)
	(segment
		(start 89.880694 -275.586952)
		(end 89.851992 -275.570188)
		(width 0.088646)
		(layer "In2.Cu")
		(net "M_B_CPU1_SA_DQ<3>")
	)
	(segment
		(start 88.629744 -276.54377)
		(end 88.629744 -276.730714)
		(width 0.088646)
		(layer "In2.Cu")
		(net "M_B_CPU1_SA_DQ<3>")
	)
	(segment
		(start 52.09794 -314.23991)
		(end 51.847496 -314.136278)
		(width 0.18288)
		(layer "In2.Cu")
		(net "M_B_CPU1_SA_DQ<3>")
	)
	(segment
		(start 83.11896 -286.314134)
		(end 80.608424 -288.82467)
		(width 0.18288)
		(layer "In2.Cu")
		(net "M_B_CPU1_SA_DQ<3>")
	)
	(segment
		(start 87.689944 -279.954228)
		(end 87.689944 -279.964134)
		(width 0.088646)
		(layer "In2.Cu")
		(net "M_B_CPU1_SA_DQ<3>")
	)
	(segment
		(start 54.496208 -315.020198)
		(end 54.326282 -314.850272)
		(width 0.18288)
		(layer "In2.Cu")
		(net "M_B_CPU1_SA_DQ<3>")
	)
	(segment
		(start 74.047604 -306.293012)
		(end 67.723258 -312.617358)
		(width 0.18288)
		(layer "In2.Cu")
		(net "M_B_CPU1_SA_DQ<3>")
	)
	(segment
		(start 64.433958 -314.173108)
		(end 63.473584 -314.173108)
		(width 0.18288)
		(layer "In2.Cu")
		(net "M_B_CPU1_SA_DQ<3>")
	)
	(segment
		(start 55.038498 -314.553346)
		(end 55.038498 -314.903358)
		(width 0.18288)
		(layer "In2.Cu")
		(net "M_B_CPU1_SA_DQ<3>")
	)
	(segment
		(start 62.604904 -314.061856)
		(end 62.604904 -314.334652)
		(width 0.18288)
		(layer "In2.Cu")
		(net "M_B_CPU1_SA_DQ<3>")
	)
	(segment
		(start 56.677052 -315.08827)
		(end 56.518302 -315.24702)
		(width 0.18288)
		(layer "In2.Cu")
		(net "M_B_CPU1_SA_DQ<3>")
	)
	(segment
		(start 62.568582 -315.293248)
		(end 62.204092 -314.928758)
		(width 0.18288)
		(layer "In2.Cu")
		(net "M_B_CPU1_SA_DQ<3>")
	)
	(segment
		(start 55.969916 -315.24702)
		(end 55.742078 -315.019182)
		(width 0.18288)
		(layer "In2.Cu")
		(net "M_B_CPU1_SA_DQ<3>")
	)
	(segment
		(start 65.497964 -314.173108)
		(end 65.137538 -314.533534)
		(width 0.18288)
		(layer "In2.Cu")
		(net "M_B_CPU1_SA_DQ<3>")
	)
	(segment
		(start 87.981282 -279.469596)
		(end 87.972392 -279.474676)
		(width 0.088646)
		(layer "In2.Cu")
		(net "M_B_CPU1_SA_DQ<3>")
	)
	(segment
		(start 67.723258 -312.617358)
		(end 67.328796 -312.617358)
		(width 0.18288)
		(layer "In2.Cu")
		(net "M_B_CPU1_SA_DQ<3>")
	)
	(segment
		(start 63.473584 -314.173108)
		(end 63.120016 -313.81954)
		(width 0.18288)
		(layer "In2.Cu")
		(net "M_B_CPU1_SA_DQ<3>")
	)
	(segment
		(start 88.350344 -276.065488)
		(end 88.490044 -276.301708)
		(width 0.088646)
		(layer "In2.Cu")
		(net "M_B_CPU1_SA_DQ<3>")
	)
	(segment
		(start 90.604594 -275.8948)
		(end 89.880694 -275.586952)
		(width 0.088646)
		(layer "In2.Cu")
		(net "M_B_CPU1_SA_DQ<3>")
	)
	(segment
		(start 62.841378 -315.293248)
		(end 62.568582 -315.293248)
		(width 0.18288)
		(layer "In2.Cu")
		(net "M_B_CPU1_SA_DQ<3>")
	)
	(segment
		(start 80.608424 -288.82467)
		(end 75.860402 -300.287182)
		(width 0.18288)
		(layer "In2.Cu")
		(net "M_B_CPU1_SA_DQ<3>")
	)
	(segment
		(start 51.847496 -314.136278)
		(end 51.477926 -313.766708)
		(width 0.18288)
		(layer "In2.Cu")
		(net "M_B_CPU1_SA_DQ<3>")
	)
	(segment
		(start 66.167508 -314.173108)
		(end 65.497964 -314.173108)
		(width 0.18288)
		(layer "In2.Cu")
		(net "M_B_CPU1_SA_DQ<3>")
	)
	(segment
		(start 61.931296 -314.928758)
		(end 61.493146 -315.366908)
		(width 0.18288)
		(layer "In2.Cu")
		(net "M_B_CPU1_SA_DQ<3>")
	)
	(segment
		(start 55.231538 -314.360306)
		(end 55.038498 -314.553346)
		(width 0.18288)
		(layer "In2.Cu")
		(net "M_B_CPU1_SA_DQ<3>")
	)
	(segment
		(start 63.061088 -314.790836)
		(end 63.061088 -315.073538)
		(width 0.18288)
		(layer "In2.Cu")
		(net "M_B_CPU1_SA_DQ<3>")
	)
	(segment
		(start 60.55487 -315.366908)
		(end 60.173362 -314.9854)
		(width 0.18288)
		(layer "In2.Cu")
		(net "M_B_CPU1_SA_DQ<3>")
	)
	(segment
		(start 85.945472 -281.141678)
		(end 85.349842 -281.141678)
		(width 0.088646)
		(layer "In2.Cu")
		(net "M_B_CPU1_SA_DQ<3>")
	)
	(segment
		(start 88.911938 -277.847044)
		(end 88.90381 -277.85187)
		(width 0.088646)
		(layer "In2.Cu")
		(net "M_B_CPU1_SA_DQ<3>")
	)
	(segment
		(start 87.511382 -280.283412)
		(end 87.502492 -280.288492)
		(width 0.088646)
		(layer "In2.Cu")
		(net "M_B_CPU1_SA_DQ<3>")
	)
	(segment
		(start 51.477926 -313.766708)
		(end 51.089814 -313.766708)
		(width 0.18288)
		(layer "In2.Cu")
		(net "M_B_CPU1_SA_DQ<3>")
	)
	(segment
		(start 54.326282 -314.850272)
		(end 54.326282 -314.380372)
		(width 0.18288)
		(layer "In2.Cu")
		(net "M_B_CPU1_SA_DQ<3>")
	)
	(segment
		(start 67.328796 -312.617358)
		(end 66.839338 -313.106816)
		(width 0.18288)
		(layer "In2.Cu")
		(net "M_B_CPU1_SA_DQ<3>")
	)
	(segment
		(start 89.478104 -275.570188)
		(end 89.477596 -275.570442)
		(width 0.088646)
		(layer "In2.Cu")
		(net "M_B_CPU1_SA_DQ<3>")
	)
	(segment
		(start 59.560714 -314.9854)
		(end 59.249564 -315.29655)
		(width 0.18288)
		(layer "In2.Cu")
		(net "M_B_CPU1_SA_DQ<3>")
	)
	(segment
		(start 62.84722 -313.81954)
		(end 62.604904 -314.061856)
		(width 0.18288)
		(layer "In2.Cu")
		(net "M_B_CPU1_SA_DQ<3>")
	)
	(segment
		(start 55.038498 -314.903358)
		(end 54.921658 -315.020198)
		(width 0.18288)
		(layer "In2.Cu")
		(net "M_B_CPU1_SA_DQ<3>")
	)
	(segment
		(start 61.493146 -315.366908)
		(end 60.55487 -315.366908)
		(width 0.18288)
		(layer "In2.Cu")
		(net "M_B_CPU1_SA_DQ<3>")
	)
	(segment
		(start 83.710272 -284.886146)
		(end 83.11896 -286.314134)
		(width 0.18288)
		(layer "In2.Cu")
		(net "M_B_CPU1_SA_DQ<3>")
	)
	(segment
		(start 85.349842 -281.141678)
		(end 84.98205 -281.141678)
		(width 0.18288)
		(layer "In2.Cu")
		(net "M_B_CPU1_SA_DQ<3>")
	)
	(segment
		(start 63.061088 -315.073538)
		(end 62.841378 -315.293248)
		(width 0.18288)
		(layer "In2.Cu")
		(net "M_B_CPU1_SA_DQ<3>")
	)
	(segment
		(start 54.18582 -314.23991)
		(end 52.09794 -314.23991)
		(width 0.18288)
		(layer "In2.Cu")
		(net "M_B_CPU1_SA_DQ<3>")
	)
	(segment
		(start 58.595514 -315.29655)
		(end 58.387234 -315.08827)
		(width 0.18288)
		(layer "In2.Cu")
		(net "M_B_CPU1_SA_DQ<3>")
	)
	(segment
		(start 62.604904 -314.334652)
		(end 63.061088 -314.790836)
		(width 0.18288)
		(layer "In2.Cu")
		(net "M_B_CPU1_SA_DQ<3>")
	)
	(segment
		(start 88.920828 -277.841964)
		(end 88.911938 -277.847044)
		(width 0.088646)
		(layer "In2.Cu")
		(net "M_B_CPU1_SA_DQ<3>")
	)
	(segment
		(start 64.794384 -314.533534)
		(end 64.433958 -314.173108)
		(width 0.18288)
		(layer "In2.Cu")
		(net "M_B_CPU1_SA_DQ<3>")
	)
	(segment
		(start 66.839338 -313.106816)
		(end 66.839338 -313.501278)
		(width 0.18288)
		(layer "In2.Cu")
		(net "M_B_CPU1_SA_DQ<3>")
	)
	(segment
		(start 88.451182 -278.65578)
		(end 88.442292 -278.66086)
		(width 0.088646)
		(layer "In2.Cu")
		(net "M_B_CPU1_SA_DQ<3>")
	)
	(segment
		(start 88.447372 -278.65705)
		(end 88.451182 -278.65578)
		(width 0.088646)
		(layer "In2.Cu")
		(net "M_B_CPU1_SA_DQ<3>")
	)
	(segment
		(start 54.326282 -314.380372)
		(end 54.18582 -314.23991)
		(width 0.18288)
		(layer "In2.Cu")
		(net "M_B_CPU1_SA_DQ<3>")
	)
	(arc
		(start 88.442292 -278.66086)
		(mid 88.237957 -278.863465)
		(end 88.159844 -279.140412)
		(width 0.088646)
		(layer "In2.Cu")
		(net "M_B_CPU1_SA_DQ<3>")
	)
	(arc
		(start 88.62822 -278.34463)
		(mid 88.577989 -278.524107)
		(end 88.447372 -278.65705)
		(width 0.088646)
		(layer "In2.Cu")
		(net "M_B_CPU1_SA_DQ<3>")
	)
	(arc
		(start 89.851992 -275.570188)
		(mid 89.665048 -275.520104)
		(end 89.478104 -275.570188)
		(width 0.088646)
		(layer "In2.Cu")
		(net "M_B_CPU1_SA_DQ<3>")
	)
	(arc
		(start 88.90381 -277.85187)
		(mid 88.702462 -278.058077)
		(end 88.628982 -278.336756)
		(width 0.088646)
		(layer "In2.Cu")
		(net "M_B_CPU1_SA_DQ<3>")
	)
	(arc
		(start 86.101682 -281.097482)
		(mid 86.026652 -281.130468)
		(end 85.945472 -281.141678)
		(width 0.088646)
		(layer "In2.Cu")
		(net "M_B_CPU1_SA_DQ<3>")
	)
	(arc
		(start 88.920828 -277.203408)
		(mid 89.099425 -277.522686)
		(end 88.920828 -277.841964)
		(width 0.088646)
		(layer "In2.Cu")
		(net "M_B_CPU1_SA_DQ<3>")
	)
	(arc
		(start 86.562692 -280.288492)
		(mid 86.360406 -280.487473)
		(end 86.280244 -280.759662)
		(width 0.088646)
		(layer "In2.Cu")
		(net "M_B_CPU1_SA_DQ<3>")
	)
	(arc
		(start 88.912192 -275.570442)
		(mid 88.724994 -275.520299)
		(end 88.537796 -275.570442)
		(width 0.088646)
		(layer "In2.Cu")
		(net "M_B_CPU1_SA_DQ<3>")
	)
	(arc
		(start 86.280244 -280.778204)
		(mid 86.232565 -280.961104)
		(end 86.101682 -281.097482)
		(width 0.088646)
		(layer "In2.Cu")
		(net "M_B_CPU1_SA_DQ<3>")
	)
	(arc
		(start 89.477596 -275.570442)
		(mid 89.194894 -275.646184)
		(end 88.912192 -275.570442)
		(width 0.088646)
		(layer "In2.Cu")
		(net "M_B_CPU1_SA_DQ<3>")
	)
	(arc
		(start 88.490044 -276.301708)
		(mid 88.592282 -276.40404)
		(end 88.629744 -276.54377)
		(width 0.088646)
		(layer "In2.Cu")
		(net "M_B_CPU1_SA_DQ<3>")
	)
	(arc
		(start 88.629744 -276.730714)
		(mid 88.710655 -277.000842)
		(end 88.911938 -277.198328)
		(width 0.088646)
		(layer "In2.Cu")
		(net "M_B_CPU1_SA_DQ<3>")
	)
	(arc
		(start 88.537796 -275.570696)
		(mid 88.400573 -275.707593)
		(end 88.350344 -275.8948)
		(width 0.088646)
		(layer "In2.Cu")
		(net "M_B_CPU1_SA_DQ<3>")
	)
	(arc
		(start 87.128096 -280.288492)
		(mid 86.845394 -280.21275)
		(end 86.562692 -280.288492)
		(width 0.088646)
		(layer "In2.Cu")
		(net "M_B_CPU1_SA_DQ<3>")
	)
	(arc
		(start 87.972392 -279.474676)
		(mid 87.768057 -279.677281)
		(end 87.689944 -279.954228)
		(width 0.088646)
		(layer "In2.Cu")
		(net "M_B_CPU1_SA_DQ<3>")
	)
	(arc
		(start 87.502492 -280.288492)
		(mid 87.315294 -280.338635)
		(end 87.128096 -280.288492)
		(width 0.088646)
		(layer "In2.Cu")
		(net "M_B_CPU1_SA_DQ<3>")
	)
	(arc
		(start 88.159844 -279.150318)
		(mid 88.112165 -279.333218)
		(end 87.981282 -279.469596)
		(width 0.088646)
		(layer "In2.Cu")
		(net "M_B_CPU1_SA_DQ<3>")
	)
	(arc
		(start 87.689944 -279.964134)
		(mid 87.642265 -280.147034)
		(end 87.511382 -280.283412)
		(width 0.088646)
		(layer "In2.Cu")
		(net "M_B_CPU1_SA_DQ<3>")
	)
	(segment
		(start 48.935894 -279.974294)
		(end 48.489362 -279.974294)
		(width 0.20066)
		(layer "F.Cu")
		(net "M_B_CPU1_SA_DQ<31>")
	)
	(segment
		(start 44.987464 -280.191718)
		(end 44.749466 -280.191718)
		(width 0.101854)
		(layer "F.Cu")
		(net "M_B_CPU1_SA_DQ<31>")
	)
	(segment
		(start 44.749466 -280.191718)
		(end 44.735242 -280.205942)
		(width 0.101854)
		(layer "F.Cu")
		(net "M_B_CPU1_SA_DQ<31>")
	)
	(segment
		(start 47.60468 -280.191718)
		(end 47.060358 -280.191718)
		(width 0.20066)
		(layer "F.Cu")
		(net "M_B_CPU1_SA_DQ<31>")
	)
	(segment
		(start 93.424248 -261.244588)
		(end 93.423994 -261.244842)
		(width 0.20066)
		(layer "F.Cu")
		(net "M_B_CPU1_SA_DQ<31>")
	)
	(segment
		(start 49.959514 -279.766776)
		(end 49.143412 -279.766776)
		(width 0.20066)
		(layer "F.Cu")
		(net "M_B_CPU1_SA_DQ<31>")
	)
	(segment
		(start 47.753778 -280.04262)
		(end 47.60468 -280.191718)
		(width 0.20066)
		(layer "F.Cu")
		(net "M_B_CPU1_SA_DQ<31>")
	)
	(segment
		(start 49.143412 -279.766776)
		(end 48.935894 -279.974294)
		(width 0.20066)
		(layer "F.Cu")
		(net "M_B_CPU1_SA_DQ<31>")
	)
	(segment
		(start 51.089814 -279.766776)
		(end 49.959514 -279.766776)
		(width 0.20066)
		(layer "F.Cu")
		(net "M_B_CPU1_SA_DQ<31>")
	)
	(segment
		(start 47.753778 -279.890982)
		(end 47.753778 -280.04262)
		(width 0.20066)
		(layer "F.Cu")
		(net "M_B_CPU1_SA_DQ<31>")
	)
	(segment
		(start 47.060358 -280.191718)
		(end 44.987464 -280.191718)
		(width 0.1016)
		(layer "F.Cu")
		(net "M_B_CPU1_SA_DQ<31>")
	)
	(segment
		(start 48.489362 -279.974294)
		(end 48.277526 -279.762458)
		(width 0.20066)
		(layer "F.Cu")
		(net "M_B_CPU1_SA_DQ<31>")
	)
	(segment
		(start 44.112942 -279.766776)
		(end 42.415714 -279.766776)
		(width 0.20066)
		(layer "F.Cu")
		(net "M_B_CPU1_SA_DQ<31>")
	)
	(segment
		(start 48.277526 -279.762458)
		(end 47.882302 -279.762458)
		(width 0.20066)
		(layer "F.Cu")
		(net "M_B_CPU1_SA_DQ<31>")
	)
	(segment
		(start 47.882302 -279.762458)
		(end 47.753778 -279.890982)
		(width 0.20066)
		(layer "F.Cu")
		(net "M_B_CPU1_SA_DQ<31>")
	)
	(segment
		(start 44.238926 -279.89276)
		(end 44.112942 -279.766776)
		(width 0.20066)
		(layer "F.Cu")
		(net "M_B_CPU1_SA_DQ<31>")
	)
	(segment
		(start 44.38142 -280.205942)
		(end 44.238926 -280.063448)
		(width 0.20066)
		(layer "F.Cu")
		(net "M_B_CPU1_SA_DQ<31>")
	)
	(segment
		(start 44.238926 -280.063448)
		(end 44.238926 -279.89276)
		(width 0.20066)
		(layer "F.Cu")
		(net "M_B_CPU1_SA_DQ<31>")
	)
	(segment
		(start 44.735242 -280.205942)
		(end 44.38142 -280.205942)
		(width 0.20066)
		(layer "F.Cu")
		(net "M_B_CPU1_SA_DQ<31>")
	)
	(segment
		(start 93.424248 -260.708902)
		(end 93.424248 -261.244588)
		(width 0.20066)
		(layer "F.Cu")
		(net "M_B_CPU1_SA_DQ<31>")
	)
	(segment
		(start 56.742076 -273.906996)
		(end 56.742076 -274.165568)
		(width 0.18288)
		(layer "In4.Cu")
		(net "M_B_CPU1_SA_DQ<31>")
	)
	(segment
		(start 67.238626 -270.031972)
		(end 65.926208 -270.031972)
		(width 0.18288)
		(layer "In4.Cu")
		(net "M_B_CPU1_SA_DQ<31>")
	)
	(segment
		(start 58.00344 -273.73072)
		(end 57.773316 -273.960844)
		(width 0.18288)
		(layer "In4.Cu")
		(net "M_B_CPU1_SA_DQ<31>")
	)
	(segment
		(start 51.623722 -279.232868)
		(end 51.089814 -279.766776)
		(width 0.18288)
		(layer "In4.Cu")
		(net "M_B_CPU1_SA_DQ<31>")
	)
	(segment
		(start 75.252072 -262.018526)
		(end 67.238626 -270.031972)
		(width 0.18288)
		(layer "In4.Cu")
		(net "M_B_CPU1_SA_DQ<31>")
	)
	(segment
		(start 57.773316 -273.960844)
		(end 57.514744 -273.960844)
		(width 0.18288)
		(layer "In4.Cu")
		(net "M_B_CPU1_SA_DQ<31>")
	)
	(segment
		(start 52.414424 -279.232868)
		(end 51.623722 -279.232868)
		(width 0.18288)
		(layer "In4.Cu")
		(net "M_B_CPU1_SA_DQ<31>")
	)
	(segment
		(start 93.423994 -261.244842)
		(end 93.11132 -261.244842)
		(width 0.088646)
		(layer "In4.Cu")
		(net "M_B_CPU1_SA_DQ<31>")
	)
	(segment
		(start 60.70473 -272.100294)
		(end 60.70473 -271.425416)
		(width 0.18288)
		(layer "In4.Cu")
		(net "M_B_CPU1_SA_DQ<31>")
	)
	(segment
		(start 57.719468 -272.929604)
		(end 57.719468 -273.188176)
		(width 0.18288)
		(layer "In4.Cu")
		(net "M_B_CPU1_SA_DQ<31>")
	)
	(segment
		(start 60.70473 -271.425416)
		(end 60.54471 -271.265396)
		(width 0.18288)
		(layer "In4.Cu")
		(net "M_B_CPU1_SA_DQ<31>")
	)
	(segment
		(start 82.783934 -260.46938)
		(end 78.991206 -260.46938)
		(width 0.18288)
		(layer "In4.Cu")
		(net "M_B_CPU1_SA_DQ<31>")
	)
	(segment
		(start 59.383676 -271.265396)
		(end 57.719468 -272.929604)
		(width 0.18288)
		(layer "In4.Cu")
		(net "M_B_CPU1_SA_DQ<31>")
	)
	(segment
		(start 88.452706 -260.749034)
		(end 88.442292 -260.75513)
		(width 0.088646)
		(layer "In4.Cu")
		(net "M_B_CPU1_SA_DQ<31>")
	)
	(segment
		(start 60.86475 -272.260314)
		(end 60.70473 -272.100294)
		(width 0.18288)
		(layer "In4.Cu")
		(net "M_B_CPU1_SA_DQ<31>")
	)
	(segment
		(start 78.991206 -260.46938)
		(end 75.252072 -262.018526)
		(width 0.18288)
		(layer "In4.Cu")
		(net "M_B_CPU1_SA_DQ<31>")
	)
	(segment
		(start 91.27236 -260.749034)
		(end 91.261946 -260.75513)
		(width 0.088646)
		(layer "In4.Cu")
		(net "M_B_CPU1_SA_DQ<31>")
	)
	(segment
		(start 65.925954 -270.032226)
		(end 64.217042 -270.032226)
		(width 0.18288)
		(layer "In4.Cu")
		(net "M_B_CPU1_SA_DQ<31>")
	)
	(segment
		(start 57.026048 -274.44954)
		(end 57.026048 -274.708112)
		(width 0.18288)
		(layer "In4.Cu")
		(net "M_B_CPU1_SA_DQ<31>")
	)
	(segment
		(start 61.39815 -271.425416)
		(end 61.39815 -272.100294)
		(width 0.18288)
		(layer "In4.Cu")
		(net "M_B_CPU1_SA_DQ<31>")
	)
	(segment
		(start 83.141566 -260.46938)
		(end 82.783934 -260.46938)
		(width 0.088646)
		(layer "In4.Cu")
		(net "M_B_CPU1_SA_DQ<31>")
	)
	(segment
		(start 56.742076 -274.165568)
		(end 57.026048 -274.44954)
		(width 0.18288)
		(layer "In4.Cu")
		(net "M_B_CPU1_SA_DQ<31>")
	)
	(segment
		(start 62.983872 -271.265396)
		(end 61.55817 -271.265396)
		(width 0.18288)
		(layer "In4.Cu")
		(net "M_B_CPU1_SA_DQ<31>")
	)
	(segment
		(start 92.211906 -260.749034)
		(end 92.201492 -260.75513)
		(width 0.088646)
		(layer "In4.Cu")
		(net "M_B_CPU1_SA_DQ<31>")
	)
	(segment
		(start 60.54471 -271.265396)
		(end 59.383676 -271.265396)
		(width 0.18288)
		(layer "In4.Cu")
		(net "M_B_CPU1_SA_DQ<31>")
	)
	(segment
		(start 90.332306 -260.749034)
		(end 90.321892 -260.75513)
		(width 0.088646)
		(layer "In4.Cu")
		(net "M_B_CPU1_SA_DQ<31>")
	)
	(segment
		(start 56.25338 -274.654264)
		(end 55.994808 -274.654264)
		(width 0.18288)
		(layer "In4.Cu")
		(net "M_B_CPU1_SA_DQ<31>")
	)
	(segment
		(start 61.39815 -272.100294)
		(end 61.23813 -272.260314)
		(width 0.18288)
		(layer "In4.Cu")
		(net "M_B_CPU1_SA_DQ<31>")
	)
	(segment
		(start 52.85613 -278.791162)
		(end 52.414424 -279.232868)
		(width 0.18288)
		(layer "In4.Cu")
		(net "M_B_CPU1_SA_DQ<31>")
	)
	(segment
		(start 83.383374 -260.711188)
		(end 83.141566 -260.46938)
		(width 0.088646)
		(layer "In4.Cu")
		(net "M_B_CPU1_SA_DQ<31>")
	)
	(segment
		(start 61.23813 -272.260314)
		(end 60.86475 -272.260314)
		(width 0.18288)
		(layer "In4.Cu")
		(net "M_B_CPU1_SA_DQ<31>")
	)
	(segment
		(start 56.795924 -274.938236)
		(end 56.537352 -274.938236)
		(width 0.18288)
		(layer "In4.Cu")
		(net "M_B_CPU1_SA_DQ<31>")
	)
	(segment
		(start 53.75402 -275.545804)
		(end 52.85613 -276.443694)
		(width 0.18288)
		(layer "In4.Cu")
		(net "M_B_CPU1_SA_DQ<31>")
	)
	(segment
		(start 55.994808 -274.654264)
		(end 55.103268 -275.545804)
		(width 0.18288)
		(layer "In4.Cu")
		(net "M_B_CPU1_SA_DQ<31>")
	)
	(segment
		(start 55.103268 -275.545804)
		(end 53.75402 -275.545804)
		(width 0.18288)
		(layer "In4.Cu")
		(net "M_B_CPU1_SA_DQ<31>")
	)
	(segment
		(start 57.026048 -274.708112)
		(end 56.795924 -274.938236)
		(width 0.18288)
		(layer "In4.Cu")
		(net "M_B_CPU1_SA_DQ<31>")
	)
	(segment
		(start 64.217042 -270.032226)
		(end 62.983872 -271.265396)
		(width 0.18288)
		(layer "In4.Cu")
		(net "M_B_CPU1_SA_DQ<31>")
	)
	(segment
		(start 52.85613 -276.443694)
		(end 52.85613 -278.791162)
		(width 0.18288)
		(layer "In4.Cu")
		(net "M_B_CPU1_SA_DQ<31>")
	)
	(segment
		(start 57.719468 -273.188176)
		(end 58.00344 -273.472148)
		(width 0.18288)
		(layer "In4.Cu")
		(net "M_B_CPU1_SA_DQ<31>")
	)
	(segment
		(start 57.230772 -273.676872)
		(end 56.9722 -273.676872)
		(width 0.18288)
		(layer "In4.Cu")
		(net "M_B_CPU1_SA_DQ<31>")
	)
	(segment
		(start 58.00344 -273.472148)
		(end 58.00344 -273.73072)
		(width 0.18288)
		(layer "In4.Cu")
		(net "M_B_CPU1_SA_DQ<31>")
	)
	(segment
		(start 56.9722 -273.676872)
		(end 56.742076 -273.906996)
		(width 0.18288)
		(layer "In4.Cu")
		(net "M_B_CPU1_SA_DQ<31>")
	)
	(segment
		(start 57.514744 -273.960844)
		(end 57.230772 -273.676872)
		(width 0.18288)
		(layer "In4.Cu")
		(net "M_B_CPU1_SA_DQ<31>")
	)
	(segment
		(start 83.743292 -260.75513)
		(end 83.738466 -260.757924)
		(width 0.088646)
		(layer "In4.Cu")
		(net "M_B_CPU1_SA_DQ<31>")
	)
	(segment
		(start 93.11132 -261.244842)
		(end 93.046042 -261.179564)
		(width 0.088646)
		(layer "In4.Cu")
		(net "M_B_CPU1_SA_DQ<31>")
	)
	(segment
		(start 56.537352 -274.938236)
		(end 56.25338 -274.654264)
		(width 0.18288)
		(layer "In4.Cu")
		(net "M_B_CPU1_SA_DQ<31>")
	)
	(segment
		(start 65.926208 -270.031972)
		(end 65.925954 -270.032226)
		(width 0.18288)
		(layer "In4.Cu")
		(net "M_B_CPU1_SA_DQ<31>")
	)
	(segment
		(start 61.55817 -271.265396)
		(end 61.39815 -271.425416)
		(width 0.18288)
		(layer "In4.Cu")
		(net "M_B_CPU1_SA_DQ<31>")
	)
	(segment
		(start 89.39276 -260.749034)
		(end 89.382346 -260.75513)
		(width 0.088646)
		(layer "In4.Cu")
		(net "M_B_CPU1_SA_DQ<31>")
	)
	(arc
		(start 86.562692 -260.75513)
		(mid 86.375494 -260.805273)
		(end 86.188296 -260.75513)
		(width 0.088646)
		(layer "In4.Cu")
		(net "M_B_CPU1_SA_DQ<31>")
	)
	(arc
		(start 84.683092 -260.75513)
		(mid 84.495894 -260.805273)
		(end 84.308696 -260.75513)
		(width 0.088646)
		(layer "In4.Cu")
		(net "M_B_CPU1_SA_DQ<31>")
	)
	(arc
		(start 91.827096 -260.75513)
		(mid 91.550537 -260.679421)
		(end 91.27236 -260.749034)
		(width 0.088646)
		(layer "In4.Cu")
		(net "M_B_CPU1_SA_DQ<31>")
	)
	(arc
		(start 93.046042 -261.179564)
		(mid 92.956928 -260.934267)
		(end 92.76715 -260.75513)
		(width 0.088646)
		(layer "In4.Cu")
		(net "M_B_CPU1_SA_DQ<31>")
	)
	(arc
		(start 88.442292 -260.75513)
		(mid 88.255094 -260.805273)
		(end 88.067896 -260.75513)
		(width 0.088646)
		(layer "In4.Cu")
		(net "M_B_CPU1_SA_DQ<31>")
	)
	(arc
		(start 89.00795 -260.75513)
		(mid 88.731137 -260.679294)
		(end 88.452706 -260.749034)
		(width 0.088646)
		(layer "In4.Cu")
		(net "M_B_CPU1_SA_DQ<31>")
	)
	(arc
		(start 92.76715 -260.75513)
		(mid 92.490337 -260.679294)
		(end 92.211906 -260.749034)
		(width 0.088646)
		(layer "In4.Cu")
		(net "M_B_CPU1_SA_DQ<31>")
	)
	(arc
		(start 88.067896 -260.75513)
		(mid 87.785194 -260.679388)
		(end 87.502492 -260.75513)
		(width 0.088646)
		(layer "In4.Cu")
		(net "M_B_CPU1_SA_DQ<31>")
	)
	(arc
		(start 89.382346 -260.75513)
		(mid 89.195148 -260.805273)
		(end 89.00795 -260.75513)
		(width 0.088646)
		(layer "In4.Cu")
		(net "M_B_CPU1_SA_DQ<31>")
	)
	(arc
		(start 83.738466 -260.757924)
		(mid 83.552995 -260.794808)
		(end 83.383374 -260.711188)
		(width 0.088646)
		(layer "In4.Cu")
		(net "M_B_CPU1_SA_DQ<31>")
	)
	(arc
		(start 85.622892 -260.75513)
		(mid 85.435694 -260.805273)
		(end 85.248496 -260.75513)
		(width 0.088646)
		(layer "In4.Cu")
		(net "M_B_CPU1_SA_DQ<31>")
	)
	(arc
		(start 86.188296 -260.75513)
		(mid 85.905594 -260.679388)
		(end 85.622892 -260.75513)
		(width 0.088646)
		(layer "In4.Cu")
		(net "M_B_CPU1_SA_DQ<31>")
	)
	(arc
		(start 90.321892 -260.75513)
		(mid 90.134694 -260.805273)
		(end 89.947496 -260.75513)
		(width 0.088646)
		(layer "In4.Cu")
		(net "M_B_CPU1_SA_DQ<31>")
	)
	(arc
		(start 89.947496 -260.75513)
		(mid 89.670937 -260.679421)
		(end 89.39276 -260.749034)
		(width 0.088646)
		(layer "In4.Cu")
		(net "M_B_CPU1_SA_DQ<31>")
	)
	(arc
		(start 90.88755 -260.75513)
		(mid 90.610737 -260.679294)
		(end 90.332306 -260.749034)
		(width 0.088646)
		(layer "In4.Cu")
		(net "M_B_CPU1_SA_DQ<31>")
	)
	(arc
		(start 87.128096 -260.75513)
		(mid 86.845394 -260.679388)
		(end 86.562692 -260.75513)
		(width 0.088646)
		(layer "In4.Cu")
		(net "M_B_CPU1_SA_DQ<31>")
	)
	(arc
		(start 92.201492 -260.75513)
		(mid 92.014294 -260.805273)
		(end 91.827096 -260.75513)
		(width 0.088646)
		(layer "In4.Cu")
		(net "M_B_CPU1_SA_DQ<31>")
	)
	(arc
		(start 91.261946 -260.75513)
		(mid 91.074748 -260.805273)
		(end 90.88755 -260.75513)
		(width 0.088646)
		(layer "In4.Cu")
		(net "M_B_CPU1_SA_DQ<31>")
	)
	(arc
		(start 87.502492 -260.75513)
		(mid 87.315294 -260.805273)
		(end 87.128096 -260.75513)
		(width 0.088646)
		(layer "In4.Cu")
		(net "M_B_CPU1_SA_DQ<31>")
	)
	(arc
		(start 85.248496 -260.75513)
		(mid 84.965794 -260.679388)
		(end 84.683092 -260.75513)
		(width 0.088646)
		(layer "In4.Cu")
		(net "M_B_CPU1_SA_DQ<31>")
	)
	(arc
		(start 84.308696 -260.75513)
		(mid 84.025994 -260.679388)
		(end 83.743292 -260.75513)
		(width 0.088646)
		(layer "In4.Cu")
		(net "M_B_CPU1_SA_DQ<31>")
	)
	(segment
		(start 49.959514 -281.466798)
		(end 48.64481 -281.466798)
		(width 0.20066)
		(layer "F.Cu")
		(net "M_B_CPU1_SA_DQ<30>")
	)
	(segment
		(start 43.562778 -281.466798)
		(end 42.415714 -281.466798)
		(width 0.20066)
		(layer "F.Cu")
		(net "M_B_CPU1_SA_DQ<30>")
	)
	(segment
		(start 47.83709 -281.18562)
		(end 47.693326 -281.041856)
		(width 0.20066)
		(layer "F.Cu")
		(net "M_B_CPU1_SA_DQ<30>")
	)
	(segment
		(start 45.000418 -281.041856)
		(end 44.745402 -281.041856)
		(width 0.101854)
		(layer "F.Cu")
		(net "M_B_CPU1_SA_DQ<30>")
	)
	(segment
		(start 51.089814 -281.466798)
		(end 49.959514 -281.466798)
		(width 0.20066)
		(layer "F.Cu")
		(net "M_B_CPU1_SA_DQ<30>")
	)
	(segment
		(start 47.83709 -281.511248)
		(end 47.83709 -281.18562)
		(width 0.20066)
		(layer "F.Cu")
		(net "M_B_CPU1_SA_DQ<30>")
	)
	(segment
		(start 44.735242 -281.031696)
		(end 43.99788 -281.031696)
		(width 0.20066)
		(layer "F.Cu")
		(net "M_B_CPU1_SA_DQ<30>")
	)
	(segment
		(start 48.432974 -281.678634)
		(end 48.004476 -281.678634)
		(width 0.20066)
		(layer "F.Cu")
		(net "M_B_CPU1_SA_DQ<30>")
	)
	(segment
		(start 43.99788 -281.031696)
		(end 43.562778 -281.466798)
		(width 0.20066)
		(layer "F.Cu")
		(net "M_B_CPU1_SA_DQ<30>")
	)
	(segment
		(start 48.64481 -281.466798)
		(end 48.432974 -281.678634)
		(width 0.20066)
		(layer "F.Cu")
		(net "M_B_CPU1_SA_DQ<30>")
	)
	(segment
		(start 93.893894 -262.058404)
		(end 93.894148 -262.058658)
		(width 0.20066)
		(layer "F.Cu")
		(net "M_B_CPU1_SA_DQ<30>")
	)
	(segment
		(start 48.004476 -281.678634)
		(end 47.83709 -281.511248)
		(width 0.20066)
		(layer "F.Cu")
		(net "M_B_CPU1_SA_DQ<30>")
	)
	(segment
		(start 47.693326 -281.041856)
		(end 47.060358 -281.041856)
		(width 0.20066)
		(layer "F.Cu")
		(net "M_B_CPU1_SA_DQ<30>")
	)
	(segment
		(start 47.060358 -281.041856)
		(end 45.000418 -281.041856)
		(width 0.1016)
		(layer "F.Cu")
		(net "M_B_CPU1_SA_DQ<30>")
	)
	(segment
		(start 93.893894 -261.522718)
		(end 93.893894 -262.058404)
		(width 0.20066)
		(layer "F.Cu")
		(net "M_B_CPU1_SA_DQ<30>")
	)
	(segment
		(start 44.745402 -281.041856)
		(end 44.735242 -281.031696)
		(width 0.101854)
		(layer "F.Cu")
		(net "M_B_CPU1_SA_DQ<30>")
	)
	(segment
		(start 51.62677 -280.929842)
		(end 51.089814 -281.466798)
		(width 0.18288)
		(layer "In4.Cu")
		(net "M_B_CPU1_SA_DQ<30>")
	)
	(segment
		(start 67.719956 -271.072102)
		(end 67.007232 -271.784826)
		(width 0.18288)
		(layer "In4.Cu")
		(net "M_B_CPU1_SA_DQ<30>")
	)
	(segment
		(start 60.565538 -273.689826)
		(end 60.319158 -273.936206)
		(width 0.18288)
		(layer "In4.Cu")
		(net "M_B_CPU1_SA_DQ<30>")
	)
	(segment
		(start 71.31812 -267.473938)
		(end 71.31812 -267.828522)
		(width 0.18288)
		(layer "In4.Cu")
		(net "M_B_CPU1_SA_DQ<30>")
	)
	(segment
		(start 61.17971 -275.45157)
		(end 60.99683 -275.63445)
		(width 0.18288)
		(layer "In4.Cu")
		(net "M_B_CPU1_SA_DQ<30>")
	)
	(segment
		(start 68.385944 -270.760698)
		(end 68.07454 -271.072102)
		(width 0.18288)
		(layer "In4.Cu")
		(net "M_B_CPU1_SA_DQ<30>")
	)
	(segment
		(start 75.963018 -262.82904)
		(end 72.295512 -266.496546)
		(width 0.18288)
		(layer "In4.Cu")
		(net "M_B_CPU1_SA_DQ<30>")
	)
	(segment
		(start 57.681876 -276.819868)
		(end 57.188354 -276.326346)
		(width 0.18288)
		(layer "In4.Cu")
		(net "M_B_CPU1_SA_DQ<30>")
	)
	(segment
		(start 79.257144 -261.46506)
		(end 75.963018 -262.82904)
		(width 0.18288)
		(layer "In4.Cu")
		(net "M_B_CPU1_SA_DQ<30>")
	)
	(segment
		(start 60.99683 -275.63445)
		(end 59.654186 -275.63445)
		(width 0.18288)
		(layer "In4.Cu")
		(net "M_B_CPU1_SA_DQ<30>")
	)
	(segment
		(start 60.319158 -273.936206)
		(end 60.319158 -274.162266)
		(width 0.18288)
		(layer "In4.Cu")
		(net "M_B_CPU1_SA_DQ<30>")
	)
	(segment
		(start 59.654186 -275.63445)
		(end 59.030616 -276.25802)
		(width 0.18288)
		(layer "In4.Cu")
		(net "M_B_CPU1_SA_DQ<30>")
	)
	(segment
		(start 92.296996 -261.5692)
		(end 92.282264 -261.560564)
		(width 0.088646)
		(layer "In4.Cu")
		(net "M_B_CPU1_SA_DQ<30>")
	)
	(segment
		(start 69.67474 -269.117318)
		(end 69.363336 -269.428722)
		(width 0.18288)
		(layer "In4.Cu")
		(net "M_B_CPU1_SA_DQ<30>")
	)
	(segment
		(start 70.029324 -269.117318)
		(end 69.67474 -269.117318)
		(width 0.18288)
		(layer "In4.Cu")
		(net "M_B_CPU1_SA_DQ<30>")
	)
	(segment
		(start 52.714906 -280.929842)
		(end 51.62677 -280.929842)
		(width 0.18288)
		(layer "In4.Cu")
		(net "M_B_CPU1_SA_DQ<30>")
	)
	(segment
		(start 61.66485 -273.689826)
		(end 60.565538 -273.689826)
		(width 0.18288)
		(layer "In4.Cu")
		(net "M_B_CPU1_SA_DQ<30>")
	)
	(segment
		(start 64.311784 -272.236184)
		(end 62.274704 -273.079972)
		(width 0.18288)
		(layer "In4.Cu")
		(net "M_B_CPU1_SA_DQ<30>")
	)
	(segment
		(start 57.188354 -276.326346)
		(end 56.929274 -276.326346)
		(width 0.18288)
		(layer "In4.Cu")
		(net "M_B_CPU1_SA_DQ<30>")
	)
	(segment
		(start 59.030616 -276.25802)
		(end 58.469784 -276.25802)
		(width 0.18288)
		(layer "In4.Cu")
		(net "M_B_CPU1_SA_DQ<30>")
	)
	(segment
		(start 70.652132 -268.139926)
		(end 70.340728 -268.45133)
		(width 0.18288)
		(layer "In4.Cu")
		(net "M_B_CPU1_SA_DQ<30>")
	)
	(segment
		(start 68.07454 -271.072102)
		(end 67.719956 -271.072102)
		(width 0.18288)
		(layer "In4.Cu")
		(net "M_B_CPU1_SA_DQ<30>")
	)
	(segment
		(start 56.910986 -277.816818)
		(end 55.82793 -277.816818)
		(width 0.18288)
		(layer "In4.Cu")
		(net "M_B_CPU1_SA_DQ<30>")
	)
	(segment
		(start 71.984108 -267.162534)
		(end 71.629524 -267.162534)
		(width 0.18288)
		(layer "In4.Cu")
		(net "M_B_CPU1_SA_DQ<30>")
	)
	(segment
		(start 69.363336 -269.428722)
		(end 69.363336 -269.783306)
		(width 0.18288)
		(layer "In4.Cu")
		(net "M_B_CPU1_SA_DQ<30>")
	)
	(segment
		(start 70.340728 -268.805914)
		(end 70.029324 -269.117318)
		(width 0.18288)
		(layer "In4.Cu")
		(net "M_B_CPU1_SA_DQ<30>")
	)
	(segment
		(start 62.274704 -273.079972)
		(end 61.66485 -273.689826)
		(width 0.18288)
		(layer "In4.Cu")
		(net "M_B_CPU1_SA_DQ<30>")
	)
	(segment
		(start 68.385944 -270.406114)
		(end 68.385944 -270.760698)
		(width 0.18288)
		(layer "In4.Cu")
		(net "M_B_CPU1_SA_DQ<30>")
	)
	(segment
		(start 58.469784 -276.25802)
		(end 57.907936 -276.819868)
		(width 0.18288)
		(layer "In4.Cu")
		(net "M_B_CPU1_SA_DQ<30>")
	)
	(segment
		(start 60.319158 -274.162266)
		(end 61.17971 -275.022818)
		(width 0.18288)
		(layer "In4.Cu")
		(net "M_B_CPU1_SA_DQ<30>")
	)
	(segment
		(start 71.31812 -267.828522)
		(end 71.006716 -268.139926)
		(width 0.18288)
		(layer "In4.Cu")
		(net "M_B_CPU1_SA_DQ<30>")
	)
	(segment
		(start 68.697348 -270.09471)
		(end 68.385944 -270.406114)
		(width 0.18288)
		(layer "In4.Cu")
		(net "M_B_CPU1_SA_DQ<30>")
	)
	(segment
		(start 93.328998 -261.623048)
		(end 93.236796 -261.5692)
		(width 0.088646)
		(layer "In4.Cu")
		(net "M_B_CPU1_SA_DQ<30>")
	)
	(segment
		(start 70.340728 -268.45133)
		(end 70.340728 -268.805914)
		(width 0.18288)
		(layer "In4.Cu")
		(net "M_B_CPU1_SA_DQ<30>")
	)
	(segment
		(start 56.679846 -276.575774)
		(end 56.679846 -276.801834)
		(width 0.18288)
		(layer "In4.Cu")
		(net "M_B_CPU1_SA_DQ<30>")
	)
	(segment
		(start 71.006716 -268.139926)
		(end 70.652132 -268.139926)
		(width 0.18288)
		(layer "In4.Cu")
		(net "M_B_CPU1_SA_DQ<30>")
	)
	(segment
		(start 72.295512 -266.85113)
		(end 71.984108 -267.162534)
		(width 0.18288)
		(layer "In4.Cu")
		(net "M_B_CPU1_SA_DQ<30>")
	)
	(segment
		(start 57.907936 -276.819868)
		(end 57.681876 -276.819868)
		(width 0.18288)
		(layer "In4.Cu")
		(net "M_B_CPU1_SA_DQ<30>")
	)
	(segment
		(start 67.007232 -271.784826)
		(end 64.763142 -271.784826)
		(width 0.18288)
		(layer "In4.Cu")
		(net "M_B_CPU1_SA_DQ<30>")
	)
	(segment
		(start 71.629524 -267.162534)
		(end 71.31812 -267.473938)
		(width 0.18288)
		(layer "In4.Cu")
		(net "M_B_CPU1_SA_DQ<30>")
	)
	(segment
		(start 55.82793 -277.816818)
		(end 52.714906 -280.929842)
		(width 0.18288)
		(layer "In4.Cu")
		(net "M_B_CPU1_SA_DQ<30>")
	)
	(segment
		(start 57.189878 -277.537926)
		(end 56.910986 -277.816818)
		(width 0.18288)
		(layer "In4.Cu")
		(net "M_B_CPU1_SA_DQ<30>")
	)
	(segment
		(start 82.783934 -261.46506)
		(end 79.257144 -261.46506)
		(width 0.18288)
		(layer "In4.Cu")
		(net "M_B_CPU1_SA_DQ<30>")
	)
	(segment
		(start 93.236796 -261.5692)
		(end 93.222064 -261.560564)
		(width 0.088646)
		(layer "In4.Cu")
		(net "M_B_CPU1_SA_DQ<30>")
	)
	(segment
		(start 83.449922 -261.46506)
		(end 82.783934 -261.46506)
		(width 0.088646)
		(layer "In4.Cu")
		(net "M_B_CPU1_SA_DQ<30>")
	)
	(segment
		(start 61.17971 -275.022818)
		(end 61.17971 -275.45157)
		(width 0.18288)
		(layer "In4.Cu")
		(net "M_B_CPU1_SA_DQ<30>")
	)
	(segment
		(start 64.763142 -271.784826)
		(end 64.311784 -272.236184)
		(width 0.18288)
		(layer "In4.Cu")
		(net "M_B_CPU1_SA_DQ<30>")
	)
	(segment
		(start 56.679846 -276.801834)
		(end 57.189878 -277.311866)
		(width 0.18288)
		(layer "In4.Cu")
		(net "M_B_CPU1_SA_DQ<30>")
	)
	(segment
		(start 56.929274 -276.326346)
		(end 56.679846 -276.575774)
		(width 0.18288)
		(layer "In4.Cu")
		(net "M_B_CPU1_SA_DQ<30>")
	)
	(segment
		(start 69.363336 -269.783306)
		(end 69.051932 -270.09471)
		(width 0.18288)
		(layer "In4.Cu")
		(net "M_B_CPU1_SA_DQ<30>")
	)
	(segment
		(start 72.295512 -266.496546)
		(end 72.295512 -266.85113)
		(width 0.18288)
		(layer "In4.Cu")
		(net "M_B_CPU1_SA_DQ<30>")
	)
	(segment
		(start 57.189878 -277.311866)
		(end 57.189878 -277.537926)
		(width 0.18288)
		(layer "In4.Cu")
		(net "M_B_CPU1_SA_DQ<30>")
	)
	(segment
		(start 69.051932 -270.09471)
		(end 68.697348 -270.09471)
		(width 0.18288)
		(layer "In4.Cu")
		(net "M_B_CPU1_SA_DQ<30>")
	)
	(arc
		(start 92.671392 -261.5692)
		(mid 92.484194 -261.619343)
		(end 92.296996 -261.5692)
		(width 0.088646)
		(layer "In4.Cu")
		(net "M_B_CPU1_SA_DQ<30>")
	)
	(arc
		(start 90.791792 -261.5692)
		(mid 90.604594 -261.619343)
		(end 90.417396 -261.5692)
		(width 0.088646)
		(layer "In4.Cu")
		(net "M_B_CPU1_SA_DQ<30>")
	)
	(arc
		(start 91.357196 -261.5692)
		(mid 91.074494 -261.493424)
		(end 90.791792 -261.5692)
		(width 0.088646)
		(layer "In4.Cu")
		(net "M_B_CPU1_SA_DQ<30>")
	)
	(arc
		(start 89.851992 -261.5692)
		(mid 89.664794 -261.619343)
		(end 89.477596 -261.5692)
		(width 0.088646)
		(layer "In4.Cu")
		(net "M_B_CPU1_SA_DQ<30>")
	)
	(arc
		(start 87.597996 -261.5692)
		(mid 87.315294 -261.493424)
		(end 87.032592 -261.5692)
		(width 0.088646)
		(layer "In4.Cu")
		(net "M_B_CPU1_SA_DQ<30>")
	)
	(arc
		(start 90.417396 -261.5692)
		(mid 90.134694 -261.493424)
		(end 89.851992 -261.5692)
		(width 0.088646)
		(layer "In4.Cu")
		(net "M_B_CPU1_SA_DQ<30>")
	)
	(arc
		(start 87.972392 -261.5692)
		(mid 87.785194 -261.619343)
		(end 87.597996 -261.5692)
		(width 0.088646)
		(layer "In4.Cu")
		(net "M_B_CPU1_SA_DQ<30>")
	)
	(arc
		(start 93.894148 -262.058658)
		(mid 93.625605 -261.822648)
		(end 93.328998 -261.623048)
		(width 0.088646)
		(layer "In4.Cu")
		(net "M_B_CPU1_SA_DQ<30>")
	)
	(arc
		(start 91.731592 -261.5692)
		(mid 91.544394 -261.619343)
		(end 91.357196 -261.5692)
		(width 0.088646)
		(layer "In4.Cu")
		(net "M_B_CPU1_SA_DQ<30>")
	)
	(arc
		(start 86.092792 -261.5692)
		(mid 85.905594 -261.619343)
		(end 85.718396 -261.5692)
		(width 0.088646)
		(layer "In4.Cu")
		(net "M_B_CPU1_SA_DQ<30>")
	)
	(arc
		(start 84.778596 -261.5692)
		(mid 84.495894 -261.493424)
		(end 84.213192 -261.5692)
		(width 0.088646)
		(layer "In4.Cu")
		(net "M_B_CPU1_SA_DQ<30>")
	)
	(arc
		(start 87.032592 -261.5692)
		(mid 86.845394 -261.619343)
		(end 86.658196 -261.5692)
		(width 0.088646)
		(layer "In4.Cu")
		(net "M_B_CPU1_SA_DQ<30>")
	)
	(arc
		(start 89.477596 -261.5692)
		(mid 89.194894 -261.493424)
		(end 88.912192 -261.5692)
		(width 0.088646)
		(layer "In4.Cu")
		(net "M_B_CPU1_SA_DQ<30>")
	)
	(arc
		(start 85.152992 -261.5692)
		(mid 84.965794 -261.619343)
		(end 84.778596 -261.5692)
		(width 0.088646)
		(layer "In4.Cu")
		(net "M_B_CPU1_SA_DQ<30>")
	)
	(arc
		(start 83.838796 -261.5692)
		(mid 83.651217 -261.491508)
		(end 83.449922 -261.46506)
		(width 0.088646)
		(layer "In4.Cu")
		(net "M_B_CPU1_SA_DQ<30>")
	)
	(arc
		(start 93.222064 -261.560564)
		(mid 92.945589 -261.493244)
		(end 92.671392 -261.5692)
		(width 0.088646)
		(layer "In4.Cu")
		(net "M_B_CPU1_SA_DQ<30>")
	)
	(arc
		(start 88.912192 -261.5692)
		(mid 88.724994 -261.619343)
		(end 88.537796 -261.5692)
		(width 0.088646)
		(layer "In4.Cu")
		(net "M_B_CPU1_SA_DQ<30>")
	)
	(arc
		(start 84.213192 -261.5692)
		(mid 84.025994 -261.619343)
		(end 83.838796 -261.5692)
		(width 0.088646)
		(layer "In4.Cu")
		(net "M_B_CPU1_SA_DQ<30>")
	)
	(arc
		(start 85.718396 -261.5692)
		(mid 85.435694 -261.493424)
		(end 85.152992 -261.5692)
		(width 0.088646)
		(layer "In4.Cu")
		(net "M_B_CPU1_SA_DQ<30>")
	)
	(arc
		(start 88.537796 -261.5692)
		(mid 88.255094 -261.493424)
		(end 87.972392 -261.5692)
		(width 0.088646)
		(layer "In4.Cu")
		(net "M_B_CPU1_SA_DQ<30>")
	)
	(arc
		(start 86.658196 -261.5692)
		(mid 86.375494 -261.493424)
		(end 86.092792 -261.5692)
		(width 0.088646)
		(layer "In4.Cu")
		(net "M_B_CPU1_SA_DQ<30>")
	)
	(arc
		(start 92.282264 -261.560564)
		(mid 92.005789 -261.493244)
		(end 91.731592 -261.5692)
		(width 0.088646)
		(layer "In4.Cu")
		(net "M_B_CPU1_SA_DQ<30>")
	)
	(segment
		(start 90.134694 -276.172676)
		(end 90.134694 -276.708616)
		(width 0.20066)
		(layer "F.Cu")
		(net "M_B_CPU1_SA_DQ<2>")
	)
	(segment
		(start 49.959514 -315.46673)
		(end 48.64481 -315.46673)
		(width 0.20066)
		(layer "F.Cu")
		(net "M_B_CPU1_SA_DQ<2>")
	)
	(segment
		(start 48.64481 -315.46673)
		(end 48.432974 -315.678566)
		(width 0.20066)
		(layer "F.Cu")
		(net "M_B_CPU1_SA_DQ<2>")
	)
	(segment
		(start 45.000418 -315.041788)
		(end 44.745402 -315.041788)
		(width 0.101854)
		(layer "F.Cu")
		(net "M_B_CPU1_SA_DQ<2>")
	)
	(segment
		(start 51.089814 -315.46673)
		(end 49.959514 -315.46673)
		(width 0.20066)
		(layer "F.Cu")
		(net "M_B_CPU1_SA_DQ<2>")
	)
	(segment
		(start 47.83709 -315.185552)
		(end 47.693326 -315.041788)
		(width 0.20066)
		(layer "F.Cu")
		(net "M_B_CPU1_SA_DQ<2>")
	)
	(segment
		(start 48.432974 -315.678566)
		(end 48.004476 -315.678566)
		(width 0.20066)
		(layer "F.Cu")
		(net "M_B_CPU1_SA_DQ<2>")
	)
	(segment
		(start 47.693326 -315.041788)
		(end 47.060358 -315.041788)
		(width 0.20066)
		(layer "F.Cu")
		(net "M_B_CPU1_SA_DQ<2>")
	)
	(segment
		(start 47.060358 -315.041788)
		(end 45.000418 -315.041788)
		(width 0.1016)
		(layer "F.Cu")
		(net "M_B_CPU1_SA_DQ<2>")
	)
	(segment
		(start 48.004476 -315.678566)
		(end 47.83709 -315.51118)
		(width 0.20066)
		(layer "F.Cu")
		(net "M_B_CPU1_SA_DQ<2>")
	)
	(segment
		(start 44.735242 -315.031628)
		(end 43.99788 -315.031628)
		(width 0.20066)
		(layer "F.Cu")
		(net "M_B_CPU1_SA_DQ<2>")
	)
	(segment
		(start 43.99788 -315.031628)
		(end 43.562778 -315.46673)
		(width 0.20066)
		(layer "F.Cu")
		(net "M_B_CPU1_SA_DQ<2>")
	)
	(segment
		(start 43.562778 -315.46673)
		(end 42.415714 -315.46673)
		(width 0.20066)
		(layer "F.Cu")
		(net "M_B_CPU1_SA_DQ<2>")
	)
	(segment
		(start 47.83709 -315.51118)
		(end 47.83709 -315.185552)
		(width 0.20066)
		(layer "F.Cu")
		(net "M_B_CPU1_SA_DQ<2>")
	)
	(segment
		(start 44.745402 -315.041788)
		(end 44.735242 -315.031628)
		(width 0.101854)
		(layer "F.Cu")
		(net "M_B_CPU1_SA_DQ<2>")
	)
	(segment
		(start 84.911438 -282.725622)
		(end 84.911438 -285.97098)
		(width 0.18288)
		(layer "In2.Cu")
		(net "M_B_CPU1_SA_DQ<2>")
	)
	(segment
		(start 76.75245 -303.840896)
		(end 75.39736 -307.112162)
		(width 0.18288)
		(layer "In2.Cu")
		(net "M_B_CPU1_SA_DQ<2>")
	)
	(segment
		(start 66.332608 -316.74181)
		(end 64.229996 -316.74181)
		(width 0.18288)
		(layer "In2.Cu")
		(net "M_B_CPU1_SA_DQ<2>")
	)
	(segment
		(start 52.84597 -318.507364)
		(end 51.899058 -318.507364)
		(width 0.18288)
		(layer "In2.Cu")
		(net "M_B_CPU1_SA_DQ<2>")
	)
	(segment
		(start 88.537796 -280.453846)
		(end 88.528906 -280.458926)
		(width 0.088646)
		(layer "In2.Cu")
		(net "M_B_CPU1_SA_DQ<2>")
	)
	(segment
		(start 89.938606 -277.027894)
		(end 89.947496 -277.032974)
		(width 0.088646)
		(layer "In2.Cu")
		(net "M_B_CPU1_SA_DQ<2>")
	)
	(segment
		(start 89.477596 -278.82596)
		(end 89.468706 -278.83104)
		(width 0.088646)
		(layer "In2.Cu")
		(net "M_B_CPU1_SA_DQ<2>")
	)
	(segment
		(start 88.350344 -280.778204)
		(end 88.350344 -280.78811)
		(width 0.088646)
		(layer "In2.Cu")
		(net "M_B_CPU1_SA_DQ<2>")
	)
	(segment
		(start 75.39736 -307.112162)
		(end 67.685158 -314.824364)
		(width 0.18288)
		(layer "In2.Cu")
		(net "M_B_CPU1_SA_DQ<2>")
	)
	(segment
		(start 54.59222 -318.507364)
		(end 53.93563 -318.507364)
		(width 0.18288)
		(layer "In2.Cu")
		(net "M_B_CPU1_SA_DQ<2>")
	)
	(segment
		(start 61.300106 -317.603632)
		(end 60.998354 -317.30188)
		(width 0.18288)
		(layer "In2.Cu")
		(net "M_B_CPU1_SA_DQ<2>")
	)
	(segment
		(start 63.368174 -317.603632)
		(end 61.300106 -317.603632)
		(width 0.18288)
		(layer "In2.Cu")
		(net "M_B_CPU1_SA_DQ<2>")
	)
	(segment
		(start 51.089814 -315.723778)
		(end 51.089814 -315.46673)
		(width 0.18288)
		(layer "In2.Cu")
		(net "M_B_CPU1_SA_DQ<2>")
	)
	(segment
		(start 89.760044 -278.336502)
		(end 89.760044 -278.346408)
		(width 0.088646)
		(layer "In2.Cu")
		(net "M_B_CPU1_SA_DQ<2>")
	)
	(segment
		(start 64.229996 -316.74181)
		(end 63.368174 -317.603632)
		(width 0.18288)
		(layer "In2.Cu")
		(net "M_B_CPU1_SA_DQ<2>")
	)
	(segment
		(start 66.578734 -316.230508)
		(end 66.578734 -316.495684)
		(width 0.18288)
		(layer "In2.Cu")
		(net "M_B_CPU1_SA_DQ<2>")
	)
	(segment
		(start 55.604664 -317.49492)
		(end 54.59222 -318.507364)
		(width 0.18288)
		(layer "In2.Cu")
		(net "M_B_CPU1_SA_DQ<2>")
	)
	(segment
		(start 57.008522 -317.49492)
		(end 55.604664 -317.49492)
		(width 0.18288)
		(layer "In2.Cu")
		(net "M_B_CPU1_SA_DQ<2>")
	)
	(segment
		(start 89.290144 -279.150318)
		(end 89.290144 -279.160224)
		(width 0.088646)
		(layer "In2.Cu")
		(net "M_B_CPU1_SA_DQ<2>")
	)
	(segment
		(start 53.23713 -317.371984)
		(end 53.03901 -317.570104)
		(width 0.18288)
		(layer "In2.Cu")
		(net "M_B_CPU1_SA_DQ<2>")
	)
	(segment
		(start 53.93563 -318.507364)
		(end 53.74259 -318.314324)
		(width 0.18288)
		(layer "In2.Cu")
		(net "M_B_CPU1_SA_DQ<2>")
	)
	(segment
		(start 84.911438 -285.97098)
		(end 84.766404 -286.321246)
		(width 0.18288)
		(layer "In2.Cu")
		(net "M_B_CPU1_SA_DQ<2>")
	)
	(segment
		(start 84.766404 -286.321246)
		(end 84.383118 -287.246314)
		(width 0.18288)
		(layer "In2.Cu")
		(net "M_B_CPU1_SA_DQ<2>")
	)
	(segment
		(start 89.007696 -279.639776)
		(end 88.998806 -279.644856)
		(width 0.088646)
		(layer "In2.Cu")
		(net "M_B_CPU1_SA_DQ<2>")
	)
	(segment
		(start 85.606128 -282.030932)
		(end 84.968842 -282.668218)
		(width 0.088646)
		(layer "In2.Cu")
		(net "M_B_CPU1_SA_DQ<2>")
	)
	(segment
		(start 51.706018 -318.314324)
		(end 51.706018 -316.568328)
		(width 0.18288)
		(layer "In2.Cu")
		(net "M_B_CPU1_SA_DQ<2>")
	)
	(segment
		(start 81.877154 -289.752278)
		(end 77.408786 -300.54042)
		(width 0.18288)
		(layer "In2.Cu")
		(net "M_B_CPU1_SA_DQ<2>")
	)
	(segment
		(start 53.74259 -317.565024)
		(end 53.54955 -317.371984)
		(width 0.18288)
		(layer "In2.Cu")
		(net "M_B_CPU1_SA_DQ<2>")
	)
	(segment
		(start 89.854024 -276.708616)
		(end 89.769696 -276.792944)
		(width 0.088646)
		(layer "In2.Cu")
		(net "M_B_CPU1_SA_DQ<2>")
	)
	(segment
		(start 51.899058 -318.507364)
		(end 51.706018 -318.314324)
		(width 0.18288)
		(layer "In2.Cu")
		(net "M_B_CPU1_SA_DQ<2>")
	)
	(segment
		(start 51.544474 -316.178438)
		(end 51.089814 -315.723778)
		(width 0.18288)
		(layer "In2.Cu")
		(net "M_B_CPU1_SA_DQ<2>")
	)
	(segment
		(start 89.947496 -278.012144)
		(end 89.938606 -278.017224)
		(width 0.088646)
		(layer "In2.Cu")
		(net "M_B_CPU1_SA_DQ<2>")
	)
	(segment
		(start 89.95537 -278.007318)
		(end 89.947496 -278.012144)
		(width 0.088646)
		(layer "In2.Cu")
		(net "M_B_CPU1_SA_DQ<2>")
	)
	(segment
		(start 53.03901 -317.570104)
		(end 53.03901 -318.314324)
		(width 0.18288)
		(layer "In2.Cu")
		(net "M_B_CPU1_SA_DQ<2>")
	)
	(segment
		(start 84.383118 -287.246314)
		(end 81.877154 -289.752278)
		(width 0.18288)
		(layer "In2.Cu")
		(net "M_B_CPU1_SA_DQ<2>")
	)
	(segment
		(start 89.947496 -277.032974)
		(end 89.959688 -277.040086)
		(width 0.088646)
		(layer "In2.Cu")
		(net "M_B_CPU1_SA_DQ<2>")
	)
	(segment
		(start 53.54955 -317.371984)
		(end 53.23713 -317.371984)
		(width 0.18288)
		(layer "In2.Cu")
		(net "M_B_CPU1_SA_DQ<2>")
	)
	(segment
		(start 87.12835 -281.267662)
		(end 87.11946 -281.272742)
		(width 0.088646)
		(layer "In2.Cu")
		(net "M_B_CPU1_SA_DQ<2>")
	)
	(segment
		(start 77.408786 -300.54042)
		(end 76.75245 -303.840896)
		(width 0.18288)
		(layer "In2.Cu")
		(net "M_B_CPU1_SA_DQ<2>")
	)
	(segment
		(start 60.998354 -317.30188)
		(end 60.606686 -317.30188)
		(width 0.18288)
		(layer "In2.Cu")
		(net "M_B_CPU1_SA_DQ<2>")
	)
	(segment
		(start 51.706018 -316.568328)
		(end 51.544474 -316.178438)
		(width 0.18288)
		(layer "In2.Cu")
		(net "M_B_CPU1_SA_DQ<2>")
	)
	(segment
		(start 53.03901 -318.314324)
		(end 52.84597 -318.507364)
		(width 0.18288)
		(layer "In2.Cu")
		(net "M_B_CPU1_SA_DQ<2>")
	)
	(segment
		(start 57.107074 -317.593472)
		(end 57.008522 -317.49492)
		(width 0.18288)
		(layer "In2.Cu")
		(net "M_B_CPU1_SA_DQ<2>")
	)
	(segment
		(start 67.685158 -314.824364)
		(end 67.685158 -315.124084)
		(width 0.18288)
		(layer "In2.Cu")
		(net "M_B_CPU1_SA_DQ<2>")
	)
	(segment
		(start 85.905594 -282.030932)
		(end 85.606128 -282.030932)
		(width 0.088646)
		(layer "In2.Cu")
		(net "M_B_CPU1_SA_DQ<2>")
	)
	(segment
		(start 87.51316 -281.273758)
		(end 87.502746 -281.267662)
		(width 0.088646)
		(layer "In2.Cu")
		(net "M_B_CPU1_SA_DQ<2>")
	)
	(segment
		(start 60.315094 -317.593472)
		(end 57.107074 -317.593472)
		(width 0.18288)
		(layer "In2.Cu")
		(net "M_B_CPU1_SA_DQ<2>")
	)
	(segment
		(start 84.968842 -282.668218)
		(end 84.911438 -282.725622)
		(width 0.18288)
		(layer "In2.Cu")
		(net "M_B_CPU1_SA_DQ<2>")
	)
	(segment
		(start 67.685158 -315.124084)
		(end 66.578734 -316.230508)
		(width 0.18288)
		(layer "In2.Cu")
		(net "M_B_CPU1_SA_DQ<2>")
	)
	(segment
		(start 60.606686 -317.30188)
		(end 60.315094 -317.593472)
		(width 0.18288)
		(layer "In2.Cu")
		(net "M_B_CPU1_SA_DQ<2>")
	)
	(segment
		(start 90.134694 -276.708616)
		(end 89.854024 -276.708616)
		(width 0.088646)
		(layer "In2.Cu")
		(net "M_B_CPU1_SA_DQ<2>")
	)
	(segment
		(start 88.820244 -279.964134)
		(end 88.820244 -279.982676)
		(width 0.088646)
		(layer "In2.Cu")
		(net "M_B_CPU1_SA_DQ<2>")
	)
	(segment
		(start 86.664546 -282.077922)
		(end 86.65845 -282.081478)
		(width 0.088646)
		(layer "In2.Cu")
		(net "M_B_CPU1_SA_DQ<2>")
	)
	(segment
		(start 53.74259 -318.314324)
		(end 53.74259 -317.565024)
		(width 0.18288)
		(layer "In2.Cu")
		(net "M_B_CPU1_SA_DQ<2>")
	)
	(segment
		(start 66.578734 -316.495684)
		(end 66.332608 -316.74181)
		(width 0.18288)
		(layer "In2.Cu")
		(net "M_B_CPU1_SA_DQ<2>")
	)
	(arc
		(start 88.820244 -279.982676)
		(mid 88.740082 -280.254865)
		(end 88.537796 -280.453846)
		(width 0.088646)
		(layer "In2.Cu")
		(net "M_B_CPU1_SA_DQ<2>")
	)
	(arc
		(start 89.468706 -278.83104)
		(mid 89.337792 -278.9674)
		(end 89.290144 -279.150318)
		(width 0.088646)
		(layer "In2.Cu")
		(net "M_B_CPU1_SA_DQ<2>")
	)
	(arc
		(start 86.103206 -282.087574)
		(mid 86.008362 -282.045423)
		(end 85.905594 -282.030932)
		(width 0.088646)
		(layer "In2.Cu")
		(net "M_B_CPU1_SA_DQ<2>")
	)
	(arc
		(start 89.290144 -279.160224)
		(mid 89.212033 -279.437173)
		(end 89.007696 -279.639776)
		(width 0.088646)
		(layer "In2.Cu")
		(net "M_B_CPU1_SA_DQ<2>")
	)
	(arc
		(start 88.067896 -281.267662)
		(mid 87.791337 -281.343405)
		(end 87.51316 -281.273758)
		(width 0.088646)
		(layer "In2.Cu")
		(net "M_B_CPU1_SA_DQ<2>")
	)
	(arc
		(start 88.998806 -279.644856)
		(mid 88.867892 -279.781216)
		(end 88.820244 -279.964134)
		(width 0.088646)
		(layer "In2.Cu")
		(net "M_B_CPU1_SA_DQ<2>")
	)
	(arc
		(start 89.760044 -278.346408)
		(mid 89.681933 -278.623357)
		(end 89.477596 -278.82596)
		(width 0.088646)
		(layer "In2.Cu")
		(net "M_B_CPU1_SA_DQ<2>")
	)
	(arc
		(start 90.230198 -277.522432)
		(mid 90.156713 -277.801108)
		(end 89.95537 -278.007318)
		(width 0.088646)
		(layer "In2.Cu")
		(net "M_B_CPU1_SA_DQ<2>")
	)
	(arc
		(start 89.769696 -276.792944)
		(mid 89.830577 -276.927358)
		(end 89.938606 -277.027894)
		(width 0.088646)
		(layer "In2.Cu")
		(net "M_B_CPU1_SA_DQ<2>")
	)
	(arc
		(start 86.940898 -281.59202)
		(mid 86.866982 -281.871522)
		(end 86.664546 -282.077922)
		(width 0.088646)
		(layer "In2.Cu")
		(net "M_B_CPU1_SA_DQ<2>")
	)
	(arc
		(start 86.65845 -282.081478)
		(mid 86.381637 -282.157348)
		(end 86.103206 -282.087574)
		(width 0.088646)
		(layer "In2.Cu")
		(net "M_B_CPU1_SA_DQ<2>")
	)
	(arc
		(start 89.959688 -277.040086)
		(mid 90.157916 -277.245934)
		(end 90.230198 -277.522432)
		(width 0.088646)
		(layer "In2.Cu")
		(net "M_B_CPU1_SA_DQ<2>")
	)
	(arc
		(start 87.11946 -281.272742)
		(mid 86.988546 -281.409102)
		(end 86.940898 -281.59202)
		(width 0.088646)
		(layer "In2.Cu")
		(net "M_B_CPU1_SA_DQ<2>")
	)
	(arc
		(start 89.938606 -278.017224)
		(mid 89.807692 -278.153584)
		(end 89.760044 -278.336502)
		(width 0.088646)
		(layer "In2.Cu")
		(net "M_B_CPU1_SA_DQ<2>")
	)
	(arc
		(start 87.502746 -281.267662)
		(mid 87.315548 -281.217519)
		(end 87.12835 -281.267662)
		(width 0.088646)
		(layer "In2.Cu")
		(net "M_B_CPU1_SA_DQ<2>")
	)
	(arc
		(start 88.528906 -280.458926)
		(mid 88.397992 -280.595286)
		(end 88.350344 -280.778204)
		(width 0.088646)
		(layer "In2.Cu")
		(net "M_B_CPU1_SA_DQ<2>")
	)
	(arc
		(start 88.350344 -280.78811)
		(mid 88.272233 -281.065059)
		(end 88.067896 -281.267662)
		(width 0.088646)
		(layer "In2.Cu")
		(net "M_B_CPU1_SA_DQ<2>")
	)
	(segment
		(start 39.649908 -280.61666)
		(end 38.315646 -280.61666)
		(width 0.20066)
		(layer "F.Cu")
		(net "M_B_CPU1_SA_DQ<29>")
	)
	(segment
		(start 40.520112 -280.673556)
		(end 40.36568 -280.827988)
		(width 0.20066)
		(layer "F.Cu")
		(net "M_B_CPU1_SA_DQ<29>")
	)
	(segment
		(start 44.22013 -280.61666)
		(end 43.795188 -280.191718)
		(width 0.20066)
		(layer "F.Cu")
		(net "M_B_CPU1_SA_DQ<29>")
	)
	(segment
		(start 40.520112 -280.345388)
		(end 40.520112 -280.673556)
		(width 0.20066)
		(layer "F.Cu")
		(net "M_B_CPU1_SA_DQ<29>")
	)
	(segment
		(start 45.859446 -280.61666)
		(end 44.22013 -280.61666)
		(width 0.20066)
		(layer "F.Cu")
		(net "M_B_CPU1_SA_DQ<29>")
	)
	(segment
		(start 92.484448 -260.708902)
		(end 92.484448 -261.244588)
		(width 0.20066)
		(layer "F.Cu")
		(net "M_B_CPU1_SA_DQ<29>")
	)
	(segment
		(start 41.3004 -280.191718)
		(end 41.29151 -280.182828)
		(width 0.1016)
		(layer "F.Cu")
		(net "M_B_CPU1_SA_DQ<29>")
	)
	(segment
		(start 40.682672 -280.182828)
		(end 40.520112 -280.345388)
		(width 0.20066)
		(layer "F.Cu")
		(net "M_B_CPU1_SA_DQ<29>")
	)
	(segment
		(start 92.484448 -261.244588)
		(end 92.484194 -261.244842)
		(width 0.20066)
		(layer "F.Cu")
		(net "M_B_CPU1_SA_DQ<29>")
	)
	(segment
		(start 43.795188 -280.191718)
		(end 43.616626 -280.191718)
		(width 0.20066)
		(layer "F.Cu")
		(net "M_B_CPU1_SA_DQ<29>")
	)
	(segment
		(start 40.36568 -280.827988)
		(end 39.861236 -280.827988)
		(width 0.20066)
		(layer "F.Cu")
		(net "M_B_CPU1_SA_DQ<29>")
	)
	(segment
		(start 46.964346 -280.61666)
		(end 45.859446 -280.61666)
		(width 0.20066)
		(layer "F.Cu")
		(net "M_B_CPU1_SA_DQ<29>")
	)
	(segment
		(start 43.616626 -280.191718)
		(end 43.285918 -280.191718)
		(width 0.101854)
		(layer "F.Cu")
		(net "M_B_CPU1_SA_DQ<29>")
	)
	(segment
		(start 39.861236 -280.827988)
		(end 39.649908 -280.61666)
		(width 0.20066)
		(layer "F.Cu")
		(net "M_B_CPU1_SA_DQ<29>")
	)
	(segment
		(start 41.29151 -280.182828)
		(end 40.682672 -280.182828)
		(width 0.20066)
		(layer "F.Cu")
		(net "M_B_CPU1_SA_DQ<29>")
	)
	(segment
		(start 43.285918 -280.191718)
		(end 41.3004 -280.191718)
		(width 0.1016)
		(layer "F.Cu")
		(net "M_B_CPU1_SA_DQ<29>")
	)
	(segment
		(start 55.329836 -277.220172)
		(end 54.240176 -277.220172)
		(width 0.18288)
		(layer "In4.Cu")
		(net "M_B_CPU1_SA_DQ<29>")
	)
	(segment
		(start 50.518568 -280.191718)
		(end 50.335688 -280.008838)
		(width 0.18288)
		(layer "In4.Cu")
		(net "M_B_CPU1_SA_DQ<29>")
	)
	(segment
		(start 92.680282 -260.925564)
		(end 92.671392 -260.920484)
		(width 0.088646)
		(layer "In4.Cu")
		(net "M_B_CPU1_SA_DQ<29>")
	)
	(segment
		(start 83.556094 -260.996176)
		(end 83.31962 -260.996176)
		(width 0.088646)
		(layer "In4.Cu")
		(net "M_B_CPU1_SA_DQ<29>")
	)
	(segment
		(start 83.31962 -260.996176)
		(end 83.290664 -260.96722)
		(width 0.088646)
		(layer "In4.Cu")
		(net "M_B_CPU1_SA_DQ<29>")
	)
	(segment
		(start 50.152808 -279.452578)
		(end 49.827688 -279.452578)
		(width 0.18288)
		(layer "In4.Cu")
		(net "M_B_CPU1_SA_DQ<29>")
	)
	(segment
		(start 48.263048 -279.635458)
		(end 48.263048 -280.008838)
		(width 0.18288)
		(layer "In4.Cu")
		(net "M_B_CPU1_SA_DQ<29>")
	)
	(segment
		(start 48.953928 -279.635458)
		(end 48.771048 -279.452578)
		(width 0.18288)
		(layer "In4.Cu")
		(net "M_B_CPU1_SA_DQ<29>")
	)
	(segment
		(start 92.796868 -261.244842)
		(end 92.854272 -261.187438)
		(width 0.088646)
		(layer "In4.Cu")
		(net "M_B_CPU1_SA_DQ<29>")
	)
	(segment
		(start 49.461928 -280.191718)
		(end 49.136808 -280.191718)
		(width 0.18288)
		(layer "In4.Cu")
		(net "M_B_CPU1_SA_DQ<29>")
	)
	(segment
		(start 50.335688 -280.008838)
		(end 50.335688 -279.635458)
		(width 0.18288)
		(layer "In4.Cu")
		(net "M_B_CPU1_SA_DQ<29>")
	)
	(segment
		(start 59.118246 -273.431762)
		(end 55.329836 -277.220172)
		(width 0.18288)
		(layer "In4.Cu")
		(net "M_B_CPU1_SA_DQ<29>")
	)
	(segment
		(start 65.259458 -270.565626)
		(end 64.007492 -271.817592)
		(width 0.18288)
		(layer "In4.Cu")
		(net "M_B_CPU1_SA_DQ<29>")
	)
	(segment
		(start 52.55768 -280.191718)
		(end 50.518568 -280.191718)
		(width 0.18288)
		(layer "In4.Cu")
		(net "M_B_CPU1_SA_DQ<29>")
	)
	(segment
		(start 54.240176 -277.220172)
		(end 53.602636 -277.857712)
		(width 0.18288)
		(layer "In4.Cu")
		(net "M_B_CPU1_SA_DQ<29>")
	)
	(segment
		(start 75.60056 -262.418322)
		(end 67.453256 -270.565626)
		(width 0.18288)
		(layer "In4.Cu")
		(net "M_B_CPU1_SA_DQ<29>")
	)
	(segment
		(start 48.080168 -280.191718)
		(end 47.389288 -280.191718)
		(width 0.18288)
		(layer "In4.Cu")
		(net "M_B_CPU1_SA_DQ<29>")
	)
	(segment
		(start 89.477596 -260.920484)
		(end 89.462864 -260.92912)
		(width 0.088646)
		(layer "In4.Cu")
		(net "M_B_CPU1_SA_DQ<29>")
	)
	(segment
		(start 47.389288 -280.191718)
		(end 46.964346 -280.61666)
		(width 0.18288)
		(layer "In4.Cu")
		(net "M_B_CPU1_SA_DQ<29>")
	)
	(segment
		(start 49.644808 -280.008838)
		(end 49.461928 -280.191718)
		(width 0.18288)
		(layer "In4.Cu")
		(net "M_B_CPU1_SA_DQ<29>")
	)
	(segment
		(start 48.445928 -279.452578)
		(end 48.263048 -279.635458)
		(width 0.18288)
		(layer "In4.Cu")
		(net "M_B_CPU1_SA_DQ<29>")
	)
	(segment
		(start 82.783934 -260.96722)
		(end 79.10449 -260.96722)
		(width 0.18288)
		(layer "In4.Cu")
		(net "M_B_CPU1_SA_DQ<29>")
	)
	(segment
		(start 53.602636 -277.857712)
		(end 53.602636 -279.146762)
		(width 0.18288)
		(layer "In4.Cu")
		(net "M_B_CPU1_SA_DQ<29>")
	)
	(segment
		(start 48.263048 -280.008838)
		(end 48.080168 -280.191718)
		(width 0.18288)
		(layer "In4.Cu")
		(net "M_B_CPU1_SA_DQ<29>")
	)
	(segment
		(start 49.644808 -279.635458)
		(end 49.644808 -280.008838)
		(width 0.18288)
		(layer "In4.Cu")
		(net "M_B_CPU1_SA_DQ<29>")
	)
	(segment
		(start 64.007492 -271.817592)
		(end 61.562488 -272.83029)
		(width 0.18288)
		(layer "In4.Cu")
		(net "M_B_CPU1_SA_DQ<29>")
	)
	(segment
		(start 92.484194 -261.244842)
		(end 92.796868 -261.244842)
		(width 0.088646)
		(layer "In4.Cu")
		(net "M_B_CPU1_SA_DQ<29>")
	)
	(segment
		(start 49.136808 -280.191718)
		(end 48.953928 -280.008838)
		(width 0.18288)
		(layer "In4.Cu")
		(net "M_B_CPU1_SA_DQ<29>")
	)
	(segment
		(start 61.562488 -272.83029)
		(end 60.57011 -272.83029)
		(width 0.18288)
		(layer "In4.Cu")
		(net "M_B_CPU1_SA_DQ<29>")
	)
	(segment
		(start 49.827688 -279.452578)
		(end 49.644808 -279.635458)
		(width 0.18288)
		(layer "In4.Cu")
		(net "M_B_CPU1_SA_DQ<29>")
	)
	(segment
		(start 91.357196 -260.920484)
		(end 91.342464 -260.92912)
		(width 0.088646)
		(layer "In4.Cu")
		(net "M_B_CPU1_SA_DQ<29>")
	)
	(segment
		(start 48.953928 -280.008838)
		(end 48.953928 -279.635458)
		(width 0.18288)
		(layer "In4.Cu")
		(net "M_B_CPU1_SA_DQ<29>")
	)
	(segment
		(start 79.10449 -260.96722)
		(end 75.60056 -262.418322)
		(width 0.18288)
		(layer "In4.Cu")
		(net "M_B_CPU1_SA_DQ<29>")
	)
	(segment
		(start 48.771048 -279.452578)
		(end 48.445928 -279.452578)
		(width 0.18288)
		(layer "In4.Cu")
		(net "M_B_CPU1_SA_DQ<29>")
	)
	(segment
		(start 67.453256 -270.565626)
		(end 65.259458 -270.565626)
		(width 0.18288)
		(layer "In4.Cu")
		(net "M_B_CPU1_SA_DQ<29>")
	)
	(segment
		(start 83.290664 -260.96722)
		(end 82.783934 -260.96722)
		(width 0.088646)
		(layer "In4.Cu")
		(net "M_B_CPU1_SA_DQ<29>")
	)
	(segment
		(start 53.602636 -279.146762)
		(end 52.55768 -280.191718)
		(width 0.18288)
		(layer "In4.Cu")
		(net "M_B_CPU1_SA_DQ<29>")
	)
	(segment
		(start 50.335688 -279.635458)
		(end 50.152808 -279.452578)
		(width 0.18288)
		(layer "In4.Cu")
		(net "M_B_CPU1_SA_DQ<29>")
	)
	(segment
		(start 60.57011 -272.83029)
		(end 59.118246 -273.431762)
		(width 0.18288)
		(layer "In4.Cu")
		(net "M_B_CPU1_SA_DQ<29>")
	)
	(arc
		(start 86.658196 -260.920484)
		(mid 86.375494 -260.996226)
		(end 86.092792 -260.920484)
		(width 0.088646)
		(layer "In4.Cu")
		(net "M_B_CPU1_SA_DQ<29>")
	)
	(arc
		(start 91.731592 -260.920484)
		(mid 91.544394 -260.870341)
		(end 91.357196 -260.920484)
		(width 0.088646)
		(layer "In4.Cu")
		(net "M_B_CPU1_SA_DQ<29>")
	)
	(arc
		(start 92.671392 -260.920484)
		(mid 92.484194 -260.870341)
		(end 92.296996 -260.920484)
		(width 0.088646)
		(layer "In4.Cu")
		(net "M_B_CPU1_SA_DQ<29>")
	)
	(arc
		(start 87.597996 -260.920484)
		(mid 87.315294 -260.996226)
		(end 87.032592 -260.920484)
		(width 0.088646)
		(layer "In4.Cu")
		(net "M_B_CPU1_SA_DQ<29>")
	)
	(arc
		(start 84.778596 -260.920484)
		(mid 84.495894 -260.996226)
		(end 84.213192 -260.920484)
		(width 0.088646)
		(layer "In4.Cu")
		(net "M_B_CPU1_SA_DQ<29>")
	)
	(arc
		(start 89.462864 -260.92912)
		(mid 89.186423 -260.996286)
		(end 88.912192 -260.920484)
		(width 0.088646)
		(layer "In4.Cu")
		(net "M_B_CPU1_SA_DQ<29>")
	)
	(arc
		(start 88.537796 -260.920484)
		(mid 88.255094 -260.996226)
		(end 87.972392 -260.920484)
		(width 0.088646)
		(layer "In4.Cu")
		(net "M_B_CPU1_SA_DQ<29>")
	)
	(arc
		(start 90.417396 -260.920484)
		(mid 90.134694 -260.996226)
		(end 89.851992 -260.920484)
		(width 0.088646)
		(layer "In4.Cu")
		(net "M_B_CPU1_SA_DQ<29>")
	)
	(arc
		(start 87.032592 -260.920484)
		(mid 86.845394 -260.870341)
		(end 86.658196 -260.920484)
		(width 0.088646)
		(layer "In4.Cu")
		(net "M_B_CPU1_SA_DQ<29>")
	)
	(arc
		(start 87.972392 -260.920484)
		(mid 87.785194 -260.870341)
		(end 87.597996 -260.920484)
		(width 0.088646)
		(layer "In4.Cu")
		(net "M_B_CPU1_SA_DQ<29>")
	)
	(arc
		(start 85.718396 -260.920484)
		(mid 85.435694 -260.996226)
		(end 85.152992 -260.920484)
		(width 0.088646)
		(layer "In4.Cu")
		(net "M_B_CPU1_SA_DQ<29>")
	)
	(arc
		(start 88.912192 -260.920484)
		(mid 88.724994 -260.870341)
		(end 88.537796 -260.920484)
		(width 0.088646)
		(layer "In4.Cu")
		(net "M_B_CPU1_SA_DQ<29>")
	)
	(arc
		(start 91.342464 -260.92912)
		(mid 91.066023 -260.996286)
		(end 90.791792 -260.920484)
		(width 0.088646)
		(layer "In4.Cu")
		(net "M_B_CPU1_SA_DQ<29>")
	)
	(arc
		(start 90.791792 -260.920484)
		(mid 90.604594 -260.870341)
		(end 90.417396 -260.920484)
		(width 0.088646)
		(layer "In4.Cu")
		(net "M_B_CPU1_SA_DQ<29>")
	)
	(arc
		(start 92.854272 -261.187438)
		(mid 92.796116 -261.037325)
		(end 92.680282 -260.925564)
		(width 0.088646)
		(layer "In4.Cu")
		(net "M_B_CPU1_SA_DQ<29>")
	)
	(arc
		(start 85.152992 -260.920484)
		(mid 84.965794 -260.870341)
		(end 84.778596 -260.920484)
		(width 0.088646)
		(layer "In4.Cu")
		(net "M_B_CPU1_SA_DQ<29>")
	)
	(arc
		(start 86.092792 -260.920484)
		(mid 85.905594 -260.870341)
		(end 85.718396 -260.920484)
		(width 0.088646)
		(layer "In4.Cu")
		(net "M_B_CPU1_SA_DQ<29>")
	)
	(arc
		(start 83.838796 -260.920484)
		(mid 83.70243 -260.976962)
		(end 83.556094 -260.996176)
		(width 0.088646)
		(layer "In4.Cu")
		(net "M_B_CPU1_SA_DQ<29>")
	)
	(arc
		(start 92.296996 -260.920484)
		(mid 92.014294 -260.996226)
		(end 91.731592 -260.920484)
		(width 0.088646)
		(layer "In4.Cu")
		(net "M_B_CPU1_SA_DQ<29>")
	)
	(arc
		(start 84.213192 -260.920484)
		(mid 84.025994 -260.870341)
		(end 83.838796 -260.920484)
		(width 0.088646)
		(layer "In4.Cu")
		(net "M_B_CPU1_SA_DQ<29>")
	)
	(arc
		(start 89.851992 -260.920484)
		(mid 89.664794 -260.870341)
		(end 89.477596 -260.920484)
		(width 0.088646)
		(layer "In4.Cu")
		(net "M_B_CPU1_SA_DQ<29>")
	)
	(segment
		(start 92.014294 -262.058404)
		(end 92.014548 -262.058658)
		(width 0.20066)
		(layer "F.Cu")
		(net "M_B_CPU1_SA_DQ<28>")
	)
	(segment
		(start 45.859446 -282.316682)
		(end 44.490386 -282.316682)
		(width 0.20066)
		(layer "F.Cu")
		(net "M_B_CPU1_SA_DQ<28>")
	)
	(segment
		(start 41.547542 -281.89174)
		(end 41.299638 -281.89174)
		(width 0.101854)
		(layer "F.Cu")
		(net "M_B_CPU1_SA_DQ<28>")
	)
	(segment
		(start 92.014294 -261.522718)
		(end 92.014294 -262.058404)
		(width 0.20066)
		(layer "F.Cu")
		(net "M_B_CPU1_SA_DQ<28>")
	)
	(segment
		(start 40.347392 -282.555442)
		(end 39.888668 -282.555442)
		(width 0.20066)
		(layer "F.Cu")
		(net "M_B_CPU1_SA_DQ<28>")
	)
	(segment
		(start 40.729662 -281.883612)
		(end 40.520112 -282.093162)
		(width 0.20066)
		(layer "F.Cu")
		(net "M_B_CPU1_SA_DQ<28>")
	)
	(segment
		(start 40.520112 -282.093162)
		(end 40.520112 -282.382722)
		(width 0.20066)
		(layer "F.Cu")
		(net "M_B_CPU1_SA_DQ<28>")
	)
	(segment
		(start 41.29151 -281.883612)
		(end 40.729662 -281.883612)
		(width 0.20066)
		(layer "F.Cu")
		(net "M_B_CPU1_SA_DQ<28>")
	)
	(segment
		(start 40.520112 -282.382722)
		(end 40.347392 -282.555442)
		(width 0.20066)
		(layer "F.Cu")
		(net "M_B_CPU1_SA_DQ<28>")
	)
	(segment
		(start 44.490386 -282.316682)
		(end 44.065444 -281.89174)
		(width 0.20066)
		(layer "F.Cu")
		(net "M_B_CPU1_SA_DQ<28>")
	)
	(segment
		(start 39.649908 -282.316682)
		(end 38.315646 -282.316682)
		(width 0.20066)
		(layer "F.Cu")
		(net "M_B_CPU1_SA_DQ<28>")
	)
	(segment
		(start 41.299638 -281.89174)
		(end 41.29151 -281.883612)
		(width 0.101854)
		(layer "F.Cu")
		(net "M_B_CPU1_SA_DQ<28>")
	)
	(segment
		(start 44.065444 -281.89174)
		(end 43.616626 -281.89174)
		(width 0.20066)
		(layer "F.Cu")
		(net "M_B_CPU1_SA_DQ<28>")
	)
	(segment
		(start 43.616626 -281.89174)
		(end 41.547542 -281.89174)
		(width 0.1016)
		(layer "F.Cu")
		(net "M_B_CPU1_SA_DQ<28>")
	)
	(segment
		(start 39.888668 -282.555442)
		(end 39.649908 -282.316682)
		(width 0.20066)
		(layer "F.Cu")
		(net "M_B_CPU1_SA_DQ<28>")
	)
	(segment
		(start 46.964346 -282.316682)
		(end 45.859446 -282.316682)
		(width 0.20066)
		(layer "F.Cu")
		(net "M_B_CPU1_SA_DQ<28>")
	)
	(segment
		(start 53.073046 -281.89174)
		(end 50.518568 -281.89174)
		(width 0.18288)
		(layer "In4.Cu")
		(net "M_B_CPU1_SA_DQ<28>")
	)
	(segment
		(start 91.644216 -261.958328)
		(end 91.261692 -261.7343)
		(width 0.088646)
		(layer "In4.Cu")
		(net "M_B_CPU1_SA_DQ<28>")
	)
	(segment
		(start 59.540902 -277.068026)
		(end 58.249312 -278.359616)
		(width 0.18288)
		(layer "In4.Cu")
		(net "M_B_CPU1_SA_DQ<28>")
	)
	(segment
		(start 50.335688 -281.265884)
		(end 50.152808 -281.083004)
		(width 0.18288)
		(layer "In4.Cu")
		(net "M_B_CPU1_SA_DQ<28>")
	)
	(segment
		(start 79.405988 -261.9629)
		(end 76.887578 -263.005824)
		(width 0.18288)
		(layer "In4.Cu")
		(net "M_B_CPU1_SA_DQ<28>")
	)
	(segment
		(start 48.953928 -281.265884)
		(end 48.771048 -281.083004)
		(width 0.18288)
		(layer "In4.Cu")
		(net "M_B_CPU1_SA_DQ<28>")
	)
	(segment
		(start 82.783934 -261.9629)
		(end 79.405988 -261.9629)
		(width 0.18288)
		(layer "In4.Cu")
		(net "M_B_CPU1_SA_DQ<28>")
	)
	(segment
		(start 47.389288 -281.89174)
		(end 46.964346 -282.316682)
		(width 0.18288)
		(layer "In4.Cu")
		(net "M_B_CPU1_SA_DQ<28>")
	)
	(segment
		(start 54.694582 -280.270204)
		(end 53.073046 -281.89174)
		(width 0.18288)
		(layer "In4.Cu")
		(net "M_B_CPU1_SA_DQ<28>")
	)
	(segment
		(start 56.083708 -278.359616)
		(end 55.31993 -279.123394)
		(width 0.18288)
		(layer "In4.Cu")
		(net "M_B_CPU1_SA_DQ<28>")
	)
	(segment
		(start 49.827688 -281.083004)
		(end 49.644808 -281.265884)
		(width 0.18288)
		(layer "In4.Cu")
		(net "M_B_CPU1_SA_DQ<28>")
	)
	(segment
		(start 82.9564 -261.9629)
		(end 82.783934 -261.9629)
		(width 0.088646)
		(layer "In4.Cu")
		(net "M_B_CPU1_SA_DQ<28>")
	)
	(segment
		(start 83.556094 -261.683754)
		(end 83.235546 -261.683754)
		(width 0.088646)
		(layer "In4.Cu")
		(net "M_B_CPU1_SA_DQ<28>")
	)
	(segment
		(start 60.286138 -277.068026)
		(end 59.540902 -277.068026)
		(width 0.18288)
		(layer "In4.Cu")
		(net "M_B_CPU1_SA_DQ<28>")
	)
	(segment
		(start 65.018412 -272.335752)
		(end 60.286138 -277.068026)
		(width 0.18288)
		(layer "In4.Cu")
		(net "M_B_CPU1_SA_DQ<28>")
	)
	(segment
		(start 48.771048 -281.083004)
		(end 48.445928 -281.083004)
		(width 0.18288)
		(layer "In4.Cu")
		(net "M_B_CPU1_SA_DQ<28>")
	)
	(segment
		(start 83.235546 -261.683754)
		(end 82.9564 -261.9629)
		(width 0.088646)
		(layer "In4.Cu")
		(net "M_B_CPU1_SA_DQ<28>")
	)
	(segment
		(start 67.55765 -272.335752)
		(end 65.018412 -272.335752)
		(width 0.18288)
		(layer "In4.Cu")
		(net "M_B_CPU1_SA_DQ<28>")
	)
	(segment
		(start 58.249312 -278.359616)
		(end 56.083708 -278.359616)
		(width 0.18288)
		(layer "In4.Cu")
		(net "M_B_CPU1_SA_DQ<28>")
	)
	(segment
		(start 48.953928 -281.70886)
		(end 48.953928 -281.265884)
		(width 0.18288)
		(layer "In4.Cu")
		(net "M_B_CPU1_SA_DQ<28>")
	)
	(segment
		(start 49.136808 -281.89174)
		(end 48.953928 -281.70886)
		(width 0.18288)
		(layer "In4.Cu")
		(net "M_B_CPU1_SA_DQ<28>")
	)
	(segment
		(start 50.335688 -281.70886)
		(end 50.335688 -281.265884)
		(width 0.18288)
		(layer "In4.Cu")
		(net "M_B_CPU1_SA_DQ<28>")
	)
	(segment
		(start 55.31993 -279.123394)
		(end 55.31993 -279.834594)
		(width 0.18288)
		(layer "In4.Cu")
		(net "M_B_CPU1_SA_DQ<28>")
	)
	(segment
		(start 49.461928 -281.89174)
		(end 49.136808 -281.89174)
		(width 0.18288)
		(layer "In4.Cu")
		(net "M_B_CPU1_SA_DQ<28>")
	)
	(segment
		(start 48.445928 -281.083004)
		(end 48.263048 -281.265884)
		(width 0.18288)
		(layer "In4.Cu")
		(net "M_B_CPU1_SA_DQ<28>")
	)
	(segment
		(start 50.518568 -281.89174)
		(end 50.335688 -281.70886)
		(width 0.18288)
		(layer "In4.Cu")
		(net "M_B_CPU1_SA_DQ<28>")
	)
	(segment
		(start 48.080168 -281.89174)
		(end 47.389288 -281.89174)
		(width 0.18288)
		(layer "In4.Cu")
		(net "M_B_CPU1_SA_DQ<28>")
	)
	(segment
		(start 48.263048 -281.265884)
		(end 48.263048 -281.70886)
		(width 0.18288)
		(layer "In4.Cu")
		(net "M_B_CPU1_SA_DQ<28>")
	)
	(segment
		(start 54.88432 -280.270204)
		(end 54.694582 -280.270204)
		(width 0.18288)
		(layer "In4.Cu")
		(net "M_B_CPU1_SA_DQ<28>")
	)
	(segment
		(start 76.887578 -263.005824)
		(end 67.55765 -272.335752)
		(width 0.18288)
		(layer "In4.Cu")
		(net "M_B_CPU1_SA_DQ<28>")
	)
	(segment
		(start 49.644808 -281.70886)
		(end 49.461928 -281.89174)
		(width 0.18288)
		(layer "In4.Cu")
		(net "M_B_CPU1_SA_DQ<28>")
	)
	(segment
		(start 49.644808 -281.265884)
		(end 49.644808 -281.70886)
		(width 0.18288)
		(layer "In4.Cu")
		(net "M_B_CPU1_SA_DQ<28>")
	)
	(segment
		(start 50.152808 -281.083004)
		(end 49.827688 -281.083004)
		(width 0.18288)
		(layer "In4.Cu")
		(net "M_B_CPU1_SA_DQ<28>")
	)
	(segment
		(start 55.31993 -279.834594)
		(end 54.88432 -280.270204)
		(width 0.18288)
		(layer "In4.Cu")
		(net "M_B_CPU1_SA_DQ<28>")
	)
	(segment
		(start 48.263048 -281.70886)
		(end 48.080168 -281.89174)
		(width 0.18288)
		(layer "In4.Cu")
		(net "M_B_CPU1_SA_DQ<28>")
	)
	(arc
		(start 83.743292 -261.7343)
		(mid 83.65302 -261.696701)
		(end 83.556094 -261.683754)
		(width 0.088646)
		(layer "In4.Cu")
		(net "M_B_CPU1_SA_DQ<28>")
	)
	(arc
		(start 91.261692 -261.7343)
		(mid 91.074494 -261.684157)
		(end 90.887296 -261.7343)
		(width 0.088646)
		(layer "In4.Cu")
		(net "M_B_CPU1_SA_DQ<28>")
	)
	(arc
		(start 90.887296 -261.7343)
		(mid 90.604594 -261.810076)
		(end 90.321892 -261.7343)
		(width 0.088646)
		(layer "In4.Cu")
		(net "M_B_CPU1_SA_DQ<28>")
	)
	(arc
		(start 86.188296 -261.7343)
		(mid 85.905594 -261.810076)
		(end 85.622892 -261.7343)
		(width 0.088646)
		(layer "In4.Cu")
		(net "M_B_CPU1_SA_DQ<28>")
	)
	(arc
		(start 85.248496 -261.7343)
		(mid 84.965794 -261.810076)
		(end 84.683092 -261.7343)
		(width 0.088646)
		(layer "In4.Cu")
		(net "M_B_CPU1_SA_DQ<28>")
	)
	(arc
		(start 92.014548 -262.058658)
		(mid 91.822692 -262.033175)
		(end 91.644216 -261.958328)
		(width 0.088646)
		(layer "In4.Cu")
		(net "M_B_CPU1_SA_DQ<28>")
	)
	(arc
		(start 90.321892 -261.7343)
		(mid 90.134694 -261.684157)
		(end 89.947496 -261.7343)
		(width 0.088646)
		(layer "In4.Cu")
		(net "M_B_CPU1_SA_DQ<28>")
	)
	(arc
		(start 85.622892 -261.7343)
		(mid 85.435694 -261.684157)
		(end 85.248496 -261.7343)
		(width 0.088646)
		(layer "In4.Cu")
		(net "M_B_CPU1_SA_DQ<28>")
	)
	(arc
		(start 89.382092 -261.7343)
		(mid 89.194894 -261.684157)
		(end 89.007696 -261.7343)
		(width 0.088646)
		(layer "In4.Cu")
		(net "M_B_CPU1_SA_DQ<28>")
	)
	(arc
		(start 87.502492 -261.7343)
		(mid 87.315294 -261.684157)
		(end 87.128096 -261.7343)
		(width 0.088646)
		(layer "In4.Cu")
		(net "M_B_CPU1_SA_DQ<28>")
	)
	(arc
		(start 84.683092 -261.7343)
		(mid 84.495894 -261.684157)
		(end 84.308696 -261.7343)
		(width 0.088646)
		(layer "In4.Cu")
		(net "M_B_CPU1_SA_DQ<28>")
	)
	(arc
		(start 88.067896 -261.7343)
		(mid 87.785194 -261.810076)
		(end 87.502492 -261.7343)
		(width 0.088646)
		(layer "In4.Cu")
		(net "M_B_CPU1_SA_DQ<28>")
	)
	(arc
		(start 89.007696 -261.7343)
		(mid 88.724994 -261.810076)
		(end 88.442292 -261.7343)
		(width 0.088646)
		(layer "In4.Cu")
		(net "M_B_CPU1_SA_DQ<28>")
	)
	(arc
		(start 87.128096 -261.7343)
		(mid 86.845394 -261.810076)
		(end 86.562692 -261.7343)
		(width 0.088646)
		(layer "In4.Cu")
		(net "M_B_CPU1_SA_DQ<28>")
	)
	(arc
		(start 84.308696 -261.7343)
		(mid 84.025994 -261.810076)
		(end 83.743292 -261.7343)
		(width 0.088646)
		(layer "In4.Cu")
		(net "M_B_CPU1_SA_DQ<28>")
	)
	(arc
		(start 89.947496 -261.7343)
		(mid 89.664794 -261.810076)
		(end 89.382092 -261.7343)
		(width 0.088646)
		(layer "In4.Cu")
		(net "M_B_CPU1_SA_DQ<28>")
	)
	(arc
		(start 86.562692 -261.7343)
		(mid 86.375494 -261.684157)
		(end 86.188296 -261.7343)
		(width 0.088646)
		(layer "In4.Cu")
		(net "M_B_CPU1_SA_DQ<28>")
	)
	(arc
		(start 88.442292 -261.7343)
		(mid 88.255094 -261.684157)
		(end 88.067896 -261.7343)
		(width 0.088646)
		(layer "In4.Cu")
		(net "M_B_CPU1_SA_DQ<28>")
	)
	(segment
		(start 49.959514 -285.716726)
		(end 49.143412 -285.716726)
		(width 0.20066)
		(layer "F.Cu")
		(net "M_B_CPU1_SA_DQ<27>")
	)
	(segment
		(start 44.238926 -286.013398)
		(end 44.238926 -285.84271)
		(width 0.20066)
		(layer "F.Cu")
		(net "M_B_CPU1_SA_DQ<27>")
	)
	(segment
		(start 44.38142 -286.155892)
		(end 44.238926 -286.013398)
		(width 0.20066)
		(layer "F.Cu")
		(net "M_B_CPU1_SA_DQ<27>")
	)
	(segment
		(start 44.238926 -285.84271)
		(end 44.112942 -285.716726)
		(width 0.20066)
		(layer "F.Cu")
		(net "M_B_CPU1_SA_DQ<27>")
	)
	(segment
		(start 51.064414 -285.716726)
		(end 49.959514 -285.716726)
		(width 0.20066)
		(layer "F.Cu")
		(net "M_B_CPU1_SA_DQ<27>")
	)
	(segment
		(start 44.735242 -286.155892)
		(end 44.38142 -286.155892)
		(width 0.20066)
		(layer "F.Cu")
		(net "M_B_CPU1_SA_DQ<27>")
	)
	(segment
		(start 44.987464 -286.141668)
		(end 44.749466 -286.141668)
		(width 0.101854)
		(layer "F.Cu")
		(net "M_B_CPU1_SA_DQ<27>")
	)
	(segment
		(start 93.893894 -263.150604)
		(end 93.893894 -263.68629)
		(width 0.20066)
		(layer "F.Cu")
		(net "M_B_CPU1_SA_DQ<27>")
	)
	(segment
		(start 47.882302 -285.712408)
		(end 47.753778 -285.840932)
		(width 0.20066)
		(layer "F.Cu")
		(net "M_B_CPU1_SA_DQ<27>")
	)
	(segment
		(start 47.60468 -286.141668)
		(end 47.060358 -286.141668)
		(width 0.20066)
		(layer "F.Cu")
		(net "M_B_CPU1_SA_DQ<27>")
	)
	(segment
		(start 47.753778 -285.99257)
		(end 47.60468 -286.141668)
		(width 0.20066)
		(layer "F.Cu")
		(net "M_B_CPU1_SA_DQ<27>")
	)
	(segment
		(start 93.893894 -263.68629)
		(end 93.894148 -263.686544)
		(width 0.20066)
		(layer "F.Cu")
		(net "M_B_CPU1_SA_DQ<27>")
	)
	(segment
		(start 48.489362 -285.924244)
		(end 48.277526 -285.712408)
		(width 0.20066)
		(layer "F.Cu")
		(net "M_B_CPU1_SA_DQ<27>")
	)
	(segment
		(start 44.112942 -285.716726)
		(end 42.415714 -285.716726)
		(width 0.20066)
		(layer "F.Cu")
		(net "M_B_CPU1_SA_DQ<27>")
	)
	(segment
		(start 47.060358 -286.141668)
		(end 44.987464 -286.141668)
		(width 0.1016)
		(layer "F.Cu")
		(net "M_B_CPU1_SA_DQ<27>")
	)
	(segment
		(start 44.749466 -286.141668)
		(end 44.735242 -286.155892)
		(width 0.101854)
		(layer "F.Cu")
		(net "M_B_CPU1_SA_DQ<27>")
	)
	(segment
		(start 49.143412 -285.716726)
		(end 48.935894 -285.924244)
		(width 0.20066)
		(layer "F.Cu")
		(net "M_B_CPU1_SA_DQ<27>")
	)
	(segment
		(start 48.277526 -285.712408)
		(end 47.882302 -285.712408)
		(width 0.20066)
		(layer "F.Cu")
		(net "M_B_CPU1_SA_DQ<27>")
	)
	(segment
		(start 47.753778 -285.840932)
		(end 47.753778 -285.99257)
		(width 0.20066)
		(layer "F.Cu")
		(net "M_B_CPU1_SA_DQ<27>")
	)
	(segment
		(start 48.935894 -285.924244)
		(end 48.489362 -285.924244)
		(width 0.20066)
		(layer "F.Cu")
		(net "M_B_CPU1_SA_DQ<27>")
	)
	(segment
		(start 59.950096 -282.055316)
		(end 59.489848 -282.055316)
		(width 0.18288)
		(layer "In4.Cu")
		(net "M_B_CPU1_SA_DQ<27>")
	)
	(segment
		(start 52.926742 -285.286958)
		(end 52.232814 -285.286958)
		(width 0.18288)
		(layer "In4.Cu")
		(net "M_B_CPU1_SA_DQ<27>")
	)
	(segment
		(start 63.656464 -279.555448)
		(end 63.430404 -279.555448)
		(width 0.18288)
		(layer "In4.Cu")
		(net "M_B_CPU1_SA_DQ<27>")
	)
	(segment
		(start 59.489848 -282.055316)
		(end 58.747152 -282.798012)
		(width 0.18288)
		(layer "In4.Cu")
		(net "M_B_CPU1_SA_DQ<27>")
	)
	(segment
		(start 61.493908 -280.996136)
		(end 61.493908 -281.254708)
		(width 0.18288)
		(layer "In4.Cu")
		(net "M_B_CPU1_SA_DQ<27>")
	)
	(segment
		(start 82.784188 -264.07618)
		(end 80.057752 -264.07618)
		(width 0.18288)
		(layer "In4.Cu")
		(net "M_B_CPU1_SA_DQ<27>")
	)
	(segment
		(start 56.463438 -282.986734)
		(end 56.463438 -283.411422)
		(width 0.18288)
		(layer "In4.Cu")
		(net "M_B_CPU1_SA_DQ<27>")
	)
	(segment
		(start 52.232814 -285.286958)
		(end 51.84267 -285.448756)
		(width 0.18288)
		(layer "In4.Cu")
		(net "M_B_CPU1_SA_DQ<27>")
	)
	(segment
		(start 63.729362 -279.48255)
		(end 63.656464 -279.555448)
		(width 0.18288)
		(layer "In4.Cu")
		(net "M_B_CPU1_SA_DQ<27>")
	)
	(segment
		(start 62.93993 -280.271982)
		(end 62.704472 -280.50744)
		(width 0.18288)
		(layer "In4.Cu")
		(net "M_B_CPU1_SA_DQ<27>")
	)
	(segment
		(start 62.93993 -280.045922)
		(end 62.93993 -280.271982)
		(width 0.18288)
		(layer "In4.Cu")
		(net "M_B_CPU1_SA_DQ<27>")
	)
	(segment
		(start 65.61201 -277.667974)
		(end 65.052702 -278.227282)
		(width 0.18288)
		(layer "In4.Cu")
		(net "M_B_CPU1_SA_DQ<27>")
	)
	(segment
		(start 57.918858 -282.615132)
		(end 57.918858 -282.278328)
		(width 0.18288)
		(layer "In4.Cu")
		(net "M_B_CPU1_SA_DQ<27>")
	)
	(segment
		(start 62.654688 -279.53462)
		(end 62.654688 -279.76068)
		(width 0.18288)
		(layer "In4.Cu")
		(net "M_B_CPU1_SA_DQ<27>")
	)
	(segment
		(start 78.702408 -264.63752)
		(end 66.744596 -276.595332)
		(width 0.18288)
		(layer "In4.Cu")
		(net "M_B_CPU1_SA_DQ<27>")
	)
	(segment
		(start 51.574446 -285.71698)
		(end 51.064668 -285.71698)
		(width 0.18288)
		(layer "In4.Cu")
		(net "M_B_CPU1_SA_DQ<27>")
	)
	(segment
		(start 61.533278 -280.316686)
		(end 61.303154 -280.54681)
		(width 0.18288)
		(layer "In4.Cu")
		(net "M_B_CPU1_SA_DQ<27>")
	)
	(segment
		(start 51.84267 -285.448756)
		(end 51.574446 -285.71698)
		(width 0.18288)
		(layer "In4.Cu")
		(net "M_B_CPU1_SA_DQ<27>")
	)
	(segment
		(start 61.982604 -280.50744)
		(end 61.79185 -280.316686)
		(width 0.18288)
		(layer "In4.Cu")
		(net "M_B_CPU1_SA_DQ<27>")
	)
	(segment
		(start 66.082672 -276.595332)
		(end 65.61201 -277.065994)
		(width 0.18288)
		(layer "In4.Cu")
		(net "M_B_CPU1_SA_DQ<27>")
	)
	(segment
		(start 61.303154 -280.805382)
		(end 61.493908 -280.996136)
		(width 0.18288)
		(layer "In4.Cu")
		(net "M_B_CPU1_SA_DQ<27>")
	)
	(segment
		(start 62.919102 -279.270206)
		(end 62.654688 -279.53462)
		(width 0.18288)
		(layer "In4.Cu")
		(net "M_B_CPU1_SA_DQ<27>")
	)
	(segment
		(start 51.064668 -285.71698)
		(end 51.064414 -285.716726)
		(width 0.18288)
		(layer "In4.Cu")
		(net "M_B_CPU1_SA_DQ<27>")
	)
	(segment
		(start 90.893138 -264.014204)
		(end 90.887296 -264.010902)
		(width 0.088646)
		(layer "In4.Cu")
		(net "M_B_CPU1_SA_DQ<27>")
	)
	(segment
		(start 61.243464 -281.505152)
		(end 60.50026 -281.505152)
		(width 0.18288)
		(layer "In4.Cu")
		(net "M_B_CPU1_SA_DQ<27>")
	)
	(segment
		(start 89.01303 -264.014204)
		(end 89.007696 -264.010902)
		(width 0.088646)
		(layer "In4.Cu")
		(net "M_B_CPU1_SA_DQ<27>")
	)
	(segment
		(start 93.536262 -263.590532)
		(end 93.145356 -263.364472)
		(width 0.088646)
		(layer "In4.Cu")
		(net "M_B_CPU1_SA_DQ<27>")
	)
	(segment
		(start 65.052702 -278.561038)
		(end 64.13119 -279.48255)
		(width 0.18288)
		(layer "In4.Cu")
		(net "M_B_CPU1_SA_DQ<27>")
	)
	(segment
		(start 83.500468 -264.07618)
		(end 82.784188 -264.07618)
		(width 0.088646)
		(layer "In4.Cu")
		(net "M_B_CPU1_SA_DQ<27>")
	)
	(segment
		(start 60.50026 -281.505152)
		(end 59.950096 -282.055316)
		(width 0.18288)
		(layer "In4.Cu")
		(net "M_B_CPU1_SA_DQ<27>")
	)
	(segment
		(start 57.410858 -282.095448)
		(end 57.227978 -282.278328)
		(width 0.18288)
		(layer "In4.Cu")
		(net "M_B_CPU1_SA_DQ<27>")
	)
	(segment
		(start 57.227978 -282.278328)
		(end 57.227978 -282.615132)
		(width 0.18288)
		(layer "In4.Cu")
		(net "M_B_CPU1_SA_DQ<27>")
	)
	(segment
		(start 57.735978 -282.095448)
		(end 57.410858 -282.095448)
		(width 0.18288)
		(layer "In4.Cu")
		(net "M_B_CPU1_SA_DQ<27>")
	)
	(segment
		(start 61.493908 -281.254708)
		(end 61.243464 -281.505152)
		(width 0.18288)
		(layer "In4.Cu")
		(net "M_B_CPU1_SA_DQ<27>")
	)
	(segment
		(start 91.832938 -263.35863)
		(end 91.827096 -263.361932)
		(width 0.088646)
		(layer "In4.Cu")
		(net "M_B_CPU1_SA_DQ<27>")
	)
	(segment
		(start 91.827096 -263.361932)
		(end 91.821254 -263.365488)
		(width 0.088646)
		(layer "In4.Cu")
		(net "M_B_CPU1_SA_DQ<27>")
	)
	(segment
		(start 58.101738 -282.798012)
		(end 57.918858 -282.615132)
		(width 0.18288)
		(layer "In4.Cu")
		(net "M_B_CPU1_SA_DQ<27>")
	)
	(segment
		(start 65.61201 -277.065994)
		(end 65.61201 -277.667974)
		(width 0.18288)
		(layer "In4.Cu")
		(net "M_B_CPU1_SA_DQ<27>")
	)
	(segment
		(start 61.79185 -280.316686)
		(end 61.533278 -280.316686)
		(width 0.18288)
		(layer "In4.Cu")
		(net "M_B_CPU1_SA_DQ<27>")
	)
	(segment
		(start 56.463438 -283.411422)
		(end 56.203342 -283.671518)
		(width 0.18288)
		(layer "In4.Cu")
		(net "M_B_CPU1_SA_DQ<27>")
	)
	(segment
		(start 62.704472 -280.50744)
		(end 61.982604 -280.50744)
		(width 0.18288)
		(layer "In4.Cu")
		(net "M_B_CPU1_SA_DQ<27>")
	)
	(segment
		(start 66.744596 -276.595332)
		(end 66.082672 -276.595332)
		(width 0.18288)
		(layer "In4.Cu")
		(net "M_B_CPU1_SA_DQ<27>")
	)
	(segment
		(start 63.145162 -279.270206)
		(end 62.919102 -279.270206)
		(width 0.18288)
		(layer "In4.Cu")
		(net "M_B_CPU1_SA_DQ<27>")
	)
	(segment
		(start 62.654688 -279.76068)
		(end 62.93993 -280.045922)
		(width 0.18288)
		(layer "In4.Cu")
		(net "M_B_CPU1_SA_DQ<27>")
	)
	(segment
		(start 64.13119 -279.48255)
		(end 63.729362 -279.48255)
		(width 0.18288)
		(layer "In4.Cu")
		(net "M_B_CPU1_SA_DQ<27>")
	)
	(segment
		(start 90.887296 -264.010902)
		(end 90.881454 -264.007346)
		(width 0.088646)
		(layer "In4.Cu")
		(net "M_B_CPU1_SA_DQ<27>")
	)
	(segment
		(start 57.918858 -282.278328)
		(end 57.735978 -282.095448)
		(width 0.18288)
		(layer "In4.Cu")
		(net "M_B_CPU1_SA_DQ<27>")
	)
	(segment
		(start 56.203342 -283.671518)
		(end 55.804562 -283.671518)
		(width 0.18288)
		(layer "In4.Cu")
		(net "M_B_CPU1_SA_DQ<27>")
	)
	(segment
		(start 56.65216 -282.798012)
		(end 56.463438 -282.986734)
		(width 0.18288)
		(layer "In4.Cu")
		(net "M_B_CPU1_SA_DQ<27>")
	)
	(segment
		(start 63.430404 -279.555448)
		(end 63.145162 -279.270206)
		(width 0.18288)
		(layer "In4.Cu")
		(net "M_B_CPU1_SA_DQ<27>")
	)
	(segment
		(start 89.951814 -264.013442)
		(end 89.947496 -264.010902)
		(width 0.088646)
		(layer "In4.Cu")
		(net "M_B_CPU1_SA_DQ<27>")
	)
	(segment
		(start 58.747152 -282.798012)
		(end 58.101738 -282.798012)
		(width 0.18288)
		(layer "In4.Cu")
		(net "M_B_CPU1_SA_DQ<27>")
	)
	(segment
		(start 61.303154 -280.54681)
		(end 61.303154 -280.805382)
		(width 0.18288)
		(layer "In4.Cu")
		(net "M_B_CPU1_SA_DQ<27>")
	)
	(segment
		(start 80.057752 -264.07618)
		(end 78.702408 -264.63752)
		(width 0.18288)
		(layer "In4.Cu")
		(net "M_B_CPU1_SA_DQ<27>")
	)
	(segment
		(start 57.227978 -282.615132)
		(end 57.045098 -282.798012)
		(width 0.18288)
		(layer "In4.Cu")
		(net "M_B_CPU1_SA_DQ<27>")
	)
	(segment
		(start 57.045098 -282.798012)
		(end 56.65216 -282.798012)
		(width 0.18288)
		(layer "In4.Cu")
		(net "M_B_CPU1_SA_DQ<27>")
	)
	(segment
		(start 92.892372 -263.295384)
		(end 92.077286 -263.295384)
		(width 0.088646)
		(layer "In4.Cu")
		(net "M_B_CPU1_SA_DQ<27>")
	)
	(segment
		(start 55.082186 -284.393894)
		(end 52.926742 -285.286958)
		(width 0.18288)
		(layer "In4.Cu")
		(net "M_B_CPU1_SA_DQ<27>")
	)
	(segment
		(start 55.804562 -283.671518)
		(end 55.082186 -284.393894)
		(width 0.18288)
		(layer "In4.Cu")
		(net "M_B_CPU1_SA_DQ<27>")
	)
	(segment
		(start 65.052702 -278.227282)
		(end 65.052702 -278.561038)
		(width 0.18288)
		(layer "In4.Cu")
		(net "M_B_CPU1_SA_DQ<27>")
	)
	(arc
		(start 91.58859 -263.663176)
		(mid 91.518128 -263.787019)
		(end 91.423236 -263.8933)
		(width 0.088646)
		(layer "In4.Cu")
		(net "M_B_CPU1_SA_DQ<27>")
	)
	(arc
		(start 91.261946 -264.010902)
		(mid 91.077992 -264.061031)
		(end 90.893138 -264.014204)
		(width 0.088646)
		(layer "In4.Cu")
		(net "M_B_CPU1_SA_DQ<27>")
	)
	(arc
		(start 93.894148 -263.686544)
		(mid 93.708878 -263.662124)
		(end 93.536262 -263.590532)
		(width 0.088646)
		(layer "In4.Cu")
		(net "M_B_CPU1_SA_DQ<27>")
	)
	(arc
		(start 87.502492 -264.010902)
		(mid 87.315294 -264.061045)
		(end 87.128096 -264.010902)
		(width 0.088646)
		(layer "In4.Cu")
		(net "M_B_CPU1_SA_DQ<27>")
	)
	(arc
		(start 92.077286 -263.295384)
		(mid 91.951077 -263.311436)
		(end 91.832938 -263.35863)
		(width 0.088646)
		(layer "In4.Cu")
		(net "M_B_CPU1_SA_DQ<27>")
	)
	(arc
		(start 91.742514 -263.424924)
		(mid 91.739249 -263.42827)
		(end 91.736164 -263.431782)
		(width 0.088646)
		(layer "In4.Cu")
		(net "M_B_CPU1_SA_DQ<27>")
	)
	(arc
		(start 86.562692 -264.010902)
		(mid 86.375494 -264.061045)
		(end 86.188296 -264.010902)
		(width 0.088646)
		(layer "In4.Cu")
		(net "M_B_CPU1_SA_DQ<27>")
	)
	(arc
		(start 91.423236 -263.8933)
		(mid 91.345717 -263.956387)
		(end 91.261946 -264.010902)
		(width 0.088646)
		(layer "In4.Cu")
		(net "M_B_CPU1_SA_DQ<27>")
	)
	(arc
		(start 90.881454 -264.007346)
		(mid 90.601319 -263.935063)
		(end 90.322146 -264.010902)
		(width 0.088646)
		(layer "In4.Cu")
		(net "M_B_CPU1_SA_DQ<27>")
	)
	(arc
		(start 88.067896 -264.010902)
		(mid 87.785194 -263.935126)
		(end 87.502492 -264.010902)
		(width 0.088646)
		(layer "In4.Cu")
		(net "M_B_CPU1_SA_DQ<27>")
	)
	(arc
		(start 89.007696 -264.010902)
		(mid 88.724994 -263.935126)
		(end 88.442292 -264.010902)
		(width 0.088646)
		(layer "In4.Cu")
		(net "M_B_CPU1_SA_DQ<27>")
	)
	(arc
		(start 89.947496 -264.010902)
		(mid 89.664938 -263.935253)
		(end 89.382346 -264.010902)
		(width 0.088646)
		(layer "In4.Cu")
		(net "M_B_CPU1_SA_DQ<27>")
	)
	(arc
		(start 84.683092 -264.010902)
		(mid 84.495894 -264.061045)
		(end 84.308696 -264.010902)
		(width 0.088646)
		(layer "In4.Cu")
		(net "M_B_CPU1_SA_DQ<27>")
	)
	(arc
		(start 86.188296 -264.010902)
		(mid 85.905594 -263.935126)
		(end 85.622892 -264.010902)
		(width 0.088646)
		(layer "In4.Cu")
		(net "M_B_CPU1_SA_DQ<27>")
	)
	(arc
		(start 93.135958 -263.359138)
		(mid 93.018266 -263.311598)
		(end 92.892372 -263.295384)
		(width 0.088646)
		(layer "In4.Cu")
		(net "M_B_CPU1_SA_DQ<27>")
	)
	(arc
		(start 83.743292 -264.010902)
		(mid 83.626198 -264.059616)
		(end 83.500468 -264.07618)
		(width 0.088646)
		(layer "In4.Cu")
		(net "M_B_CPU1_SA_DQ<27>")
	)
	(arc
		(start 85.248496 -264.010902)
		(mid 84.965794 -263.935126)
		(end 84.683092 -264.010902)
		(width 0.088646)
		(layer "In4.Cu")
		(net "M_B_CPU1_SA_DQ<27>")
	)
	(arc
		(start 91.628976 -263.583928)
		(mid 91.607586 -263.622942)
		(end 91.58859 -263.663176)
		(width 0.088646)
		(layer "In4.Cu")
		(net "M_B_CPU1_SA_DQ<27>")
	)
	(arc
		(start 93.145356 -263.364472)
		(mid 93.140677 -263.361771)
		(end 93.135958 -263.359138)
		(width 0.088646)
		(layer "In4.Cu")
		(net "M_B_CPU1_SA_DQ<27>")
	)
	(arc
		(start 87.128096 -264.010902)
		(mid 86.845394 -263.935126)
		(end 86.562692 -264.010902)
		(width 0.088646)
		(layer "In4.Cu")
		(net "M_B_CPU1_SA_DQ<27>")
	)
	(arc
		(start 91.821254 -263.365488)
		(mid 91.780028 -263.392747)
		(end 91.742514 -263.424924)
		(width 0.088646)
		(layer "In4.Cu")
		(net "M_B_CPU1_SA_DQ<27>")
	)
	(arc
		(start 91.736164 -263.431782)
		(mid 91.679532 -263.505715)
		(end 91.628976 -263.583928)
		(width 0.088646)
		(layer "In4.Cu")
		(net "M_B_CPU1_SA_DQ<27>")
	)
	(arc
		(start 89.382346 -264.010902)
		(mid 89.198138 -264.061158)
		(end 89.01303 -264.014204)
		(width 0.088646)
		(layer "In4.Cu")
		(net "M_B_CPU1_SA_DQ<27>")
	)
	(arc
		(start 85.622892 -264.010902)
		(mid 85.435694 -264.061045)
		(end 85.248496 -264.010902)
		(width 0.088646)
		(layer "In4.Cu")
		(net "M_B_CPU1_SA_DQ<27>")
	)
	(arc
		(start 88.442292 -264.010902)
		(mid 88.255094 -264.061045)
		(end 88.067896 -264.010902)
		(width 0.088646)
		(layer "In4.Cu")
		(net "M_B_CPU1_SA_DQ<27>")
	)
	(arc
		(start 84.308696 -264.010902)
		(mid 84.025994 -263.935126)
		(end 83.743292 -264.010902)
		(width 0.088646)
		(layer "In4.Cu")
		(net "M_B_CPU1_SA_DQ<27>")
	)
	(arc
		(start 90.322146 -264.010902)
		(mid 90.137309 -264.061163)
		(end 89.951814 -264.013442)
		(width 0.088646)
		(layer "In4.Cu")
		(net "M_B_CPU1_SA_DQ<27>")
	)
	(segment
		(start 51.064414 -287.416748)
		(end 49.959514 -287.416748)
		(width 0.20066)
		(layer "F.Cu")
		(net "M_B_CPU1_SA_DQ<26>")
	)
	(segment
		(start 47.83709 -287.13557)
		(end 47.693326 -286.991806)
		(width 0.20066)
		(layer "F.Cu")
		(net "M_B_CPU1_SA_DQ<26>")
	)
	(segment
		(start 93.424248 -263.96442)
		(end 93.423994 -263.964674)
		(width 0.20066)
		(layer "F.Cu")
		(net "M_B_CPU1_SA_DQ<26>")
	)
	(segment
		(start 45.000418 -286.991806)
		(end 44.745402 -286.991806)
		(width 0.101854)
		(layer "F.Cu")
		(net "M_B_CPU1_SA_DQ<26>")
	)
	(segment
		(start 43.99788 -286.981646)
		(end 43.562778 -287.416748)
		(width 0.20066)
		(layer "F.Cu")
		(net "M_B_CPU1_SA_DQ<26>")
	)
	(segment
		(start 47.83709 -287.461198)
		(end 47.83709 -287.13557)
		(width 0.20066)
		(layer "F.Cu")
		(net "M_B_CPU1_SA_DQ<26>")
	)
	(segment
		(start 44.735242 -286.981646)
		(end 43.99788 -286.981646)
		(width 0.20066)
		(layer "F.Cu")
		(net "M_B_CPU1_SA_DQ<26>")
	)
	(segment
		(start 43.562778 -287.416748)
		(end 42.415714 -287.416748)
		(width 0.20066)
		(layer "F.Cu")
		(net "M_B_CPU1_SA_DQ<26>")
	)
	(segment
		(start 47.060358 -286.991806)
		(end 45.000418 -286.991806)
		(width 0.1016)
		(layer "F.Cu")
		(net "M_B_CPU1_SA_DQ<26>")
	)
	(segment
		(start 48.64481 -287.416748)
		(end 48.432974 -287.628584)
		(width 0.20066)
		(layer "F.Cu")
		(net "M_B_CPU1_SA_DQ<26>")
	)
	(segment
		(start 47.693326 -286.991806)
		(end 47.060358 -286.991806)
		(width 0.20066)
		(layer "F.Cu")
		(net "M_B_CPU1_SA_DQ<26>")
	)
	(segment
		(start 44.745402 -286.991806)
		(end 44.735242 -286.981646)
		(width 0.101854)
		(layer "F.Cu")
		(net "M_B_CPU1_SA_DQ<26>")
	)
	(segment
		(start 49.959514 -287.416748)
		(end 48.64481 -287.416748)
		(width 0.20066)
		(layer "F.Cu")
		(net "M_B_CPU1_SA_DQ<26>")
	)
	(segment
		(start 48.432974 -287.628584)
		(end 48.004476 -287.628584)
		(width 0.20066)
		(layer "F.Cu")
		(net "M_B_CPU1_SA_DQ<26>")
	)
	(segment
		(start 48.004476 -287.628584)
		(end 47.83709 -287.461198)
		(width 0.20066)
		(layer "F.Cu")
		(net "M_B_CPU1_SA_DQ<26>")
	)
	(segment
		(start 93.423994 -263.964674)
		(end 93.423994 -264.50036)
		(width 0.20066)
		(layer "F.Cu")
		(net "M_B_CPU1_SA_DQ<26>")
	)
	(segment
		(start 79.623666 -265.912346)
		(end 67.87388 -277.662132)
		(width 0.18288)
		(layer "In4.Cu")
		(net "M_B_CPU1_SA_DQ<26>")
	)
	(segment
		(start 59.145678 -284.546294)
		(end 58.985658 -284.386274)
		(width 0.18288)
		(layer "In4.Cu")
		(net "M_B_CPU1_SA_DQ<26>")
	)
	(segment
		(start 90.332306 -264.995914)
		(end 90.321892 -264.989818)
		(width 0.088646)
		(layer "In4.Cu")
		(net "M_B_CPU1_SA_DQ<26>")
	)
	(segment
		(start 64.372236 -282.771596)
		(end 63.518796 -282.771596)
		(width 0.18288)
		(layer "In4.Cu")
		(net "M_B_CPU1_SA_DQ<26>")
	)
	(segment
		(start 51.694334 -287.416748)
		(end 51.064414 -287.416748)
		(width 0.18288)
		(layer "In4.Cu")
		(net "M_B_CPU1_SA_DQ<26>")
	)
	(segment
		(start 67.87388 -277.662132)
		(end 66.556128 -280.843228)
		(width 0.18288)
		(layer "In4.Cu")
		(net "M_B_CPU1_SA_DQ<26>")
	)
	(segment
		(start 64.802004 -281.717496)
		(end 64.802004 -281.943556)
		(width 0.18288)
		(layer "In4.Cu")
		(net "M_B_CPU1_SA_DQ<26>")
	)
	(segment
		(start 61.69152 -284.250892)
		(end 61.5315 -284.090872)
		(width 0.18288)
		(layer "In4.Cu")
		(net "M_B_CPU1_SA_DQ<26>")
	)
	(segment
		(start 54.201568 -286.930084)
		(end 54.0258 -287.105852)
		(width 0.18288)
		(layer "In4.Cu")
		(net "M_B_CPU1_SA_DQ<26>")
	)
	(segment
		(start 56.65597 -285.981394)
		(end 55.65902 -285.981394)
		(width 0.18288)
		(layer "In4.Cu")
		(net "M_B_CPU1_SA_DQ<26>")
	)
	(segment
		(start 59.856116 -284.546294)
		(end 59.856116 -284.9372)
		(width 0.18288)
		(layer "In4.Cu")
		(net "M_B_CPU1_SA_DQ<26>")
	)
	(segment
		(start 55.40121 -286.4739)
		(end 54.945026 -286.930084)
		(width 0.18288)
		(layer "In4.Cu")
		(net "M_B_CPU1_SA_DQ<26>")
	)
	(segment
		(start 63.518796 -282.771596)
		(end 62.0395 -284.250892)
		(width 0.18288)
		(layer "In4.Cu")
		(net "M_B_CPU1_SA_DQ<26>")
	)
	(segment
		(start 65.403222 -281.116278)
		(end 64.802004 -281.717496)
		(width 0.18288)
		(layer "In4.Cu")
		(net "M_B_CPU1_SA_DQ<26>")
	)
	(segment
		(start 55.65902 -285.981394)
		(end 55.40121 -286.239204)
		(width 0.18288)
		(layer "In4.Cu")
		(net "M_B_CPU1_SA_DQ<26>")
	)
	(segment
		(start 52.60594 -287.105852)
		(end 52.49164 -286.991552)
		(width 0.18288)
		(layer "In4.Cu")
		(net "M_B_CPU1_SA_DQ<26>")
	)
	(segment
		(start 52.11953 -286.991552)
		(end 51.694334 -287.416748)
		(width 0.18288)
		(layer "In4.Cu")
		(net "M_B_CPU1_SA_DQ<26>")
	)
	(segment
		(start 91.827096 -264.989818)
		(end 91.816682 -264.995914)
		(width 0.088646)
		(layer "In4.Cu")
		(net "M_B_CPU1_SA_DQ<26>")
	)
	(segment
		(start 61.5315 -283.762196)
		(end 61.37148 -283.602176)
		(width 0.18288)
		(layer "In4.Cu")
		(net "M_B_CPU1_SA_DQ<26>")
	)
	(segment
		(start 82.991706 -265.5697)
		(end 82.784188 -265.5697)
		(width 0.088646)
		(layer "In4.Cu")
		(net "M_B_CPU1_SA_DQ<26>")
	)
	(segment
		(start 64.802004 -281.943556)
		(end 64.88811 -282.029662)
		(width 0.18288)
		(layer "In4.Cu")
		(net "M_B_CPU1_SA_DQ<26>")
	)
	(segment
		(start 83.493864 -265.067542)
		(end 82.991706 -265.5697)
		(width 0.088646)
		(layer "In4.Cu")
		(net "M_B_CPU1_SA_DQ<26>")
	)
	(segment
		(start 62.0395 -284.250892)
		(end 61.69152 -284.250892)
		(width 0.18288)
		(layer "In4.Cu")
		(net "M_B_CPU1_SA_DQ<26>")
	)
	(segment
		(start 61.5315 -284.090872)
		(end 61.5315 -283.762196)
		(width 0.18288)
		(layer "In4.Cu")
		(net "M_B_CPU1_SA_DQ<26>")
	)
	(segment
		(start 92.845382 -264.944606)
		(end 92.76715 -264.989818)
		(width 0.088646)
		(layer "In4.Cu")
		(net "M_B_CPU1_SA_DQ<26>")
	)
	(segment
		(start 58.25109 -284.386274)
		(end 56.65597 -285.981394)
		(width 0.18288)
		(layer "In4.Cu")
		(net "M_B_CPU1_SA_DQ<26>")
	)
	(segment
		(start 59.673236 -285.12008)
		(end 59.328558 -285.12008)
		(width 0.18288)
		(layer "In4.Cu")
		(net "M_B_CPU1_SA_DQ<26>")
	)
	(segment
		(start 82.784188 -265.5697)
		(end 80.450436 -265.5697)
		(width 0.18288)
		(layer "In4.Cu")
		(net "M_B_CPU1_SA_DQ<26>")
	)
	(segment
		(start 54.0258 -287.105852)
		(end 52.60594 -287.105852)
		(width 0.18288)
		(layer "In4.Cu")
		(net "M_B_CPU1_SA_DQ<26>")
	)
	(segment
		(start 61.37148 -283.602176)
		(end 60.89142 -283.602176)
		(width 0.18288)
		(layer "In4.Cu")
		(net "M_B_CPU1_SA_DQ<26>")
	)
	(segment
		(start 55.40121 -286.239204)
		(end 55.40121 -286.4739)
		(width 0.18288)
		(layer "In4.Cu")
		(net "M_B_CPU1_SA_DQ<26>")
	)
	(segment
		(start 58.985658 -284.386274)
		(end 58.25109 -284.386274)
		(width 0.18288)
		(layer "In4.Cu")
		(net "M_B_CPU1_SA_DQ<26>")
	)
	(segment
		(start 64.88811 -282.255722)
		(end 64.372236 -282.771596)
		(width 0.18288)
		(layer "In4.Cu")
		(net "M_B_CPU1_SA_DQ<26>")
	)
	(segment
		(start 60.89142 -283.602176)
		(end 60.69838 -283.795216)
		(width 0.18288)
		(layer "In4.Cu")
		(net "M_B_CPU1_SA_DQ<26>")
	)
	(segment
		(start 54.945026 -286.930084)
		(end 54.201568 -286.930084)
		(width 0.18288)
		(layer "In4.Cu")
		(net "M_B_CPU1_SA_DQ<26>")
	)
	(segment
		(start 59.856116 -284.9372)
		(end 59.673236 -285.12008)
		(width 0.18288)
		(layer "In4.Cu")
		(net "M_B_CPU1_SA_DQ<26>")
	)
	(segment
		(start 66.556128 -280.843228)
		(end 66.283078 -281.116278)
		(width 0.18288)
		(layer "In4.Cu")
		(net "M_B_CPU1_SA_DQ<26>")
	)
	(segment
		(start 92.211906 -264.995914)
		(end 92.201492 -264.989818)
		(width 0.088646)
		(layer "In4.Cu")
		(net "M_B_CPU1_SA_DQ<26>")
	)
	(segment
		(start 60.016136 -284.386274)
		(end 59.856116 -284.546294)
		(width 0.18288)
		(layer "In4.Cu")
		(net "M_B_CPU1_SA_DQ<26>")
	)
	(segment
		(start 66.283078 -281.116278)
		(end 65.403222 -281.116278)
		(width 0.18288)
		(layer "In4.Cu")
		(net "M_B_CPU1_SA_DQ<26>")
	)
	(segment
		(start 64.88811 -282.029662)
		(end 64.88811 -282.255722)
		(width 0.18288)
		(layer "In4.Cu")
		(net "M_B_CPU1_SA_DQ<26>")
	)
	(segment
		(start 59.328558 -285.12008)
		(end 59.145678 -284.9372)
		(width 0.18288)
		(layer "In4.Cu")
		(net "M_B_CPU1_SA_DQ<26>")
	)
	(segment
		(start 60.69838 -284.23108)
		(end 60.543186 -284.386274)
		(width 0.18288)
		(layer "In4.Cu")
		(net "M_B_CPU1_SA_DQ<26>")
	)
	(segment
		(start 59.145678 -284.9372)
		(end 59.145678 -284.546294)
		(width 0.18288)
		(layer "In4.Cu")
		(net "M_B_CPU1_SA_DQ<26>")
	)
	(segment
		(start 80.450436 -265.5697)
		(end 79.623666 -265.912346)
		(width 0.18288)
		(layer "In4.Cu")
		(net "M_B_CPU1_SA_DQ<26>")
	)
	(segment
		(start 60.543186 -284.386274)
		(end 60.016136 -284.386274)
		(width 0.18288)
		(layer "In4.Cu")
		(net "M_B_CPU1_SA_DQ<26>")
	)
	(segment
		(start 52.49164 -286.991552)
		(end 52.11953 -286.991552)
		(width 0.18288)
		(layer "In4.Cu")
		(net "M_B_CPU1_SA_DQ<26>")
	)
	(segment
		(start 60.69838 -283.795216)
		(end 60.69838 -284.23108)
		(width 0.18288)
		(layer "In4.Cu")
		(net "M_B_CPU1_SA_DQ<26>")
	)
	(arc
		(start 93.423994 -264.50036)
		(mid 93.149213 -264.741401)
		(end 92.845382 -264.944606)
		(width 0.088646)
		(layer "In4.Cu")
		(net "M_B_CPU1_SA_DQ<26>")
	)
	(arc
		(start 91.261946 -264.989818)
		(mid 91.074748 -264.939675)
		(end 90.88755 -264.989818)
		(width 0.088646)
		(layer "In4.Cu")
		(net "M_B_CPU1_SA_DQ<26>")
	)
	(arc
		(start 84.683092 -264.989818)
		(mid 84.495894 -264.939675)
		(end 84.308696 -264.989818)
		(width 0.088646)
		(layer "In4.Cu")
		(net "M_B_CPU1_SA_DQ<26>")
	)
	(arc
		(start 89.382092 -264.989818)
		(mid 89.194894 -264.939675)
		(end 89.007696 -264.989818)
		(width 0.088646)
		(layer "In4.Cu")
		(net "M_B_CPU1_SA_DQ<26>")
	)
	(arc
		(start 85.622892 -264.989818)
		(mid 85.435694 -264.939675)
		(end 85.248496 -264.989818)
		(width 0.088646)
		(layer "In4.Cu")
		(net "M_B_CPU1_SA_DQ<26>")
	)
	(arc
		(start 86.188296 -264.989818)
		(mid 85.905594 -265.065594)
		(end 85.622892 -264.989818)
		(width 0.088646)
		(layer "In4.Cu")
		(net "M_B_CPU1_SA_DQ<26>")
	)
	(arc
		(start 85.248496 -264.989818)
		(mid 84.965794 -265.065594)
		(end 84.683092 -264.989818)
		(width 0.088646)
		(layer "In4.Cu")
		(net "M_B_CPU1_SA_DQ<26>")
	)
	(arc
		(start 90.321892 -264.989818)
		(mid 90.134694 -264.939675)
		(end 89.947496 -264.989818)
		(width 0.088646)
		(layer "In4.Cu")
		(net "M_B_CPU1_SA_DQ<26>")
	)
	(arc
		(start 86.562692 -264.989818)
		(mid 86.375494 -264.939675)
		(end 86.188296 -264.989818)
		(width 0.088646)
		(layer "In4.Cu")
		(net "M_B_CPU1_SA_DQ<26>")
	)
	(arc
		(start 87.502492 -264.989818)
		(mid 87.315294 -264.939675)
		(end 87.128096 -264.989818)
		(width 0.088646)
		(layer "In4.Cu")
		(net "M_B_CPU1_SA_DQ<26>")
	)
	(arc
		(start 83.794092 -265.01598)
		(mid 83.737503 -264.997365)
		(end 83.678268 -264.991088)
		(width 0.088646)
		(layer "In4.Cu")
		(net "M_B_CPU1_SA_DQ<26>")
	)
	(arc
		(start 92.76715 -264.989818)
		(mid 92.490337 -265.065688)
		(end 92.211906 -264.995914)
		(width 0.088646)
		(layer "In4.Cu")
		(net "M_B_CPU1_SA_DQ<26>")
	)
	(arc
		(start 91.816682 -264.995914)
		(mid 91.538504 -265.065637)
		(end 91.261946 -264.989818)
		(width 0.088646)
		(layer "In4.Cu")
		(net "M_B_CPU1_SA_DQ<26>")
	)
	(arc
		(start 88.067896 -264.989818)
		(mid 87.785194 -265.065594)
		(end 87.502492 -264.989818)
		(width 0.088646)
		(layer "In4.Cu")
		(net "M_B_CPU1_SA_DQ<26>")
	)
	(arc
		(start 90.88755 -264.989818)
		(mid 90.610737 -265.065688)
		(end 90.332306 -264.995914)
		(width 0.088646)
		(layer "In4.Cu")
		(net "M_B_CPU1_SA_DQ<26>")
	)
	(arc
		(start 89.947496 -264.989818)
		(mid 89.664794 -265.065594)
		(end 89.382092 -264.989818)
		(width 0.088646)
		(layer "In4.Cu")
		(net "M_B_CPU1_SA_DQ<26>")
	)
	(arc
		(start 83.678268 -264.991088)
		(mid 83.578471 -265.010975)
		(end 83.493864 -265.067542)
		(width 0.088646)
		(layer "In4.Cu")
		(net "M_B_CPU1_SA_DQ<26>")
	)
	(arc
		(start 89.007696 -264.989818)
		(mid 88.724994 -265.065594)
		(end 88.442292 -264.989818)
		(width 0.088646)
		(layer "In4.Cu")
		(net "M_B_CPU1_SA_DQ<26>")
	)
	(arc
		(start 84.308696 -264.989818)
		(mid 84.054539 -265.064987)
		(end 83.794092 -265.01598)
		(width 0.088646)
		(layer "In4.Cu")
		(net "M_B_CPU1_SA_DQ<26>")
	)
	(arc
		(start 87.128096 -264.989818)
		(mid 86.845394 -265.065594)
		(end 86.562692 -264.989818)
		(width 0.088646)
		(layer "In4.Cu")
		(net "M_B_CPU1_SA_DQ<26>")
	)
	(arc
		(start 92.201492 -264.989818)
		(mid 92.014294 -264.939675)
		(end 91.827096 -264.989818)
		(width 0.088646)
		(layer "In4.Cu")
		(net "M_B_CPU1_SA_DQ<26>")
	)
	(arc
		(start 88.442292 -264.989818)
		(mid 88.255094 -264.939675)
		(end 88.067896 -264.989818)
		(width 0.088646)
		(layer "In4.Cu")
		(net "M_B_CPU1_SA_DQ<26>")
	)
	(segment
		(start 40.520112 -286.295338)
		(end 40.520112 -286.623506)
		(width 0.20066)
		(layer "F.Cu")
		(net "M_B_CPU1_SA_DQ<25>")
	)
	(segment
		(start 41.3004 -286.141668)
		(end 41.29151 -286.132778)
		(width 0.1016)
		(layer "F.Cu")
		(net "M_B_CPU1_SA_DQ<25>")
	)
	(segment
		(start 43.616626 -286.141668)
		(end 43.285918 -286.141668)
		(width 0.101854)
		(layer "F.Cu")
		(net "M_B_CPU1_SA_DQ<25>")
	)
	(segment
		(start 45.859446 -286.56661)
		(end 44.22013 -286.56661)
		(width 0.20066)
		(layer "F.Cu")
		(net "M_B_CPU1_SA_DQ<25>")
	)
	(segment
		(start 40.682672 -286.132778)
		(end 40.520112 -286.295338)
		(width 0.20066)
		(layer "F.Cu")
		(net "M_B_CPU1_SA_DQ<25>")
	)
	(segment
		(start 41.29151 -286.132778)
		(end 40.682672 -286.132778)
		(width 0.20066)
		(layer "F.Cu")
		(net "M_B_CPU1_SA_DQ<25>")
	)
	(segment
		(start 40.520112 -286.623506)
		(end 40.36568 -286.777938)
		(width 0.20066)
		(layer "F.Cu")
		(net "M_B_CPU1_SA_DQ<25>")
	)
	(segment
		(start 40.36568 -286.777938)
		(end 39.861236 -286.777938)
		(width 0.20066)
		(layer "F.Cu")
		(net "M_B_CPU1_SA_DQ<25>")
	)
	(segment
		(start 92.014294 -263.68629)
		(end 92.014548 -263.686544)
		(width 0.20066)
		(layer "F.Cu")
		(net "M_B_CPU1_SA_DQ<25>")
	)
	(segment
		(start 44.22013 -286.56661)
		(end 43.795188 -286.141668)
		(width 0.20066)
		(layer "F.Cu")
		(net "M_B_CPU1_SA_DQ<25>")
	)
	(segment
		(start 39.649908 -286.56661)
		(end 38.315646 -286.56661)
		(width 0.20066)
		(layer "F.Cu")
		(net "M_B_CPU1_SA_DQ<25>")
	)
	(segment
		(start 92.014294 -263.150604)
		(end 92.014294 -263.68629)
		(width 0.20066)
		(layer "F.Cu")
		(net "M_B_CPU1_SA_DQ<25>")
	)
	(segment
		(start 43.285918 -286.141668)
		(end 41.3004 -286.141668)
		(width 0.1016)
		(layer "F.Cu")
		(net "M_B_CPU1_SA_DQ<25>")
	)
	(segment
		(start 39.861236 -286.777938)
		(end 39.649908 -286.56661)
		(width 0.20066)
		(layer "F.Cu")
		(net "M_B_CPU1_SA_DQ<25>")
	)
	(segment
		(start 43.795188 -286.141668)
		(end 43.616626 -286.141668)
		(width 0.20066)
		(layer "F.Cu")
		(net "M_B_CPU1_SA_DQ<25>")
	)
	(segment
		(start 46.964346 -286.56661)
		(end 45.859446 -286.56661)
		(width 0.20066)
		(layer "F.Cu")
		(net "M_B_CPU1_SA_DQ<25>")
	)
	(segment
		(start 49.228502 -285.958788)
		(end 49.228502 -285.56077)
		(width 0.18288)
		(layer "In4.Cu")
		(net "M_B_CPU1_SA_DQ<25>")
	)
	(segment
		(start 63.915544 -280.015696)
		(end 62.780926 -281.150314)
		(width 0.18288)
		(layer "In4.Cu")
		(net "M_B_CPU1_SA_DQ<25>")
	)
	(segment
		(start 60.729368 -282.071826)
		(end 60.119514 -282.68168)
		(width 0.18288)
		(layer "In4.Cu")
		(net "M_B_CPU1_SA_DQ<25>")
	)
	(segment
		(start 62.780926 -281.150314)
		(end 62.780926 -281.514042)
		(width 0.18288)
		(layer "In4.Cu")
		(net "M_B_CPU1_SA_DQ<25>")
	)
	(segment
		(start 83.838796 -264.176002)
		(end 83.216242 -264.535412)
		(width 0.088646)
		(layer "In4.Cu")
		(net "M_B_CPU1_SA_DQ<25>")
	)
	(segment
		(start 78.971902 -265.085322)
		(end 65.564258 -278.492966)
		(width 0.18288)
		(layer "In4.Cu")
		(net "M_B_CPU1_SA_DQ<25>")
	)
	(segment
		(start 52.737766 -285.909512)
		(end 52.50561 -286.141668)
		(width 0.18288)
		(layer "In4.Cu")
		(net "M_B_CPU1_SA_DQ<25>")
	)
	(segment
		(start 58.92546 -283.354526)
		(end 57.805066 -283.354526)
		(width 0.18288)
		(layer "In4.Cu")
		(net "M_B_CPU1_SA_DQ<25>")
	)
	(segment
		(start 52.50561 -286.141668)
		(end 49.411382 -286.141668)
		(width 0.18288)
		(layer "In4.Cu")
		(net "M_B_CPU1_SA_DQ<25>")
	)
	(segment
		(start 62.780926 -281.514042)
		(end 62.223142 -282.071826)
		(width 0.18288)
		(layer "In4.Cu")
		(net "M_B_CPU1_SA_DQ<25>")
	)
	(segment
		(start 49.411382 -286.141668)
		(end 49.228502 -285.958788)
		(width 0.18288)
		(layer "In4.Cu")
		(net "M_B_CPU1_SA_DQ<25>")
	)
	(segment
		(start 49.045622 -285.37789)
		(end 48.720502 -285.37789)
		(width 0.18288)
		(layer "In4.Cu")
		(net "M_B_CPU1_SA_DQ<25>")
	)
	(segment
		(start 49.228502 -285.56077)
		(end 49.045622 -285.37789)
		(width 0.18288)
		(layer "In4.Cu")
		(net "M_B_CPU1_SA_DQ<25>")
	)
	(segment
		(start 60.119514 -282.68168)
		(end 59.598306 -282.68168)
		(width 0.18288)
		(layer "In4.Cu")
		(net "M_B_CPU1_SA_DQ<25>")
	)
	(segment
		(start 65.564258 -279.080214)
		(end 64.628776 -280.015696)
		(width 0.18288)
		(layer "In4.Cu")
		(net "M_B_CPU1_SA_DQ<25>")
	)
	(segment
		(start 83.071716 -264.57402)
		(end 82.784188 -264.57402)
		(width 0.088646)
		(layer "In4.Cu")
		(net "M_B_CPU1_SA_DQ<25>")
	)
	(segment
		(start 90.797888 -264.179304)
		(end 90.792046 -264.175748)
		(width 0.088646)
		(layer "In4.Cu")
		(net "M_B_CPU1_SA_DQ<25>")
	)
	(segment
		(start 91.437714 -264.129266)
		(end 91.357196 -264.175748)
		(width 0.088646)
		(layer "In4.Cu")
		(net "M_B_CPU1_SA_DQ<25>")
	)
	(segment
		(start 57.805066 -283.354526)
		(end 56.826912 -284.33268)
		(width 0.18288)
		(layer "In4.Cu")
		(net "M_B_CPU1_SA_DQ<25>")
	)
	(segment
		(start 47.389288 -286.141668)
		(end 46.964346 -286.56661)
		(width 0.18288)
		(layer "In4.Cu")
		(net "M_B_CPU1_SA_DQ<25>")
	)
	(segment
		(start 56.54421 -284.33268)
		(end 52.737766 -285.909512)
		(width 0.18288)
		(layer "In4.Cu")
		(net "M_B_CPU1_SA_DQ<25>")
	)
	(segment
		(start 62.223142 -282.071826)
		(end 60.729368 -282.071826)
		(width 0.18288)
		(layer "In4.Cu")
		(net "M_B_CPU1_SA_DQ<25>")
	)
	(segment
		(start 88.917018 -264.178542)
		(end 88.912192 -264.176002)
		(width 0.088646)
		(layer "In4.Cu")
		(net "M_B_CPU1_SA_DQ<25>")
	)
	(segment
		(start 80.207104 -264.57402)
		(end 78.971902 -265.085322)
		(width 0.18288)
		(layer "In4.Cu")
		(net "M_B_CPU1_SA_DQ<25>")
	)
	(segment
		(start 90.792046 -264.175748)
		(end 90.786204 -264.172446)
		(width 0.088646)
		(layer "In4.Cu")
		(net "M_B_CPU1_SA_DQ<25>")
	)
	(segment
		(start 48.537622 -285.958788)
		(end 48.354742 -286.141668)
		(width 0.18288)
		(layer "In4.Cu")
		(net "M_B_CPU1_SA_DQ<25>")
	)
	(segment
		(start 56.826912 -284.33268)
		(end 56.54421 -284.33268)
		(width 0.18288)
		(layer "In4.Cu")
		(net "M_B_CPU1_SA_DQ<25>")
	)
	(segment
		(start 59.598306 -282.68168)
		(end 58.92546 -283.354526)
		(width 0.18288)
		(layer "In4.Cu")
		(net "M_B_CPU1_SA_DQ<25>")
	)
	(segment
		(start 48.720502 -285.37789)
		(end 48.537622 -285.56077)
		(width 0.18288)
		(layer "In4.Cu")
		(net "M_B_CPU1_SA_DQ<25>")
	)
	(segment
		(start 48.537622 -285.56077)
		(end 48.537622 -285.958788)
		(width 0.18288)
		(layer "In4.Cu")
		(net "M_B_CPU1_SA_DQ<25>")
	)
	(segment
		(start 64.628776 -280.015696)
		(end 63.915544 -280.015696)
		(width 0.18288)
		(layer "In4.Cu")
		(net "M_B_CPU1_SA_DQ<25>")
	)
	(segment
		(start 65.564258 -278.492966)
		(end 65.564258 -279.080214)
		(width 0.18288)
		(layer "In4.Cu")
		(net "M_B_CPU1_SA_DQ<25>")
	)
	(segment
		(start 89.855802 -264.178034)
		(end 89.852246 -264.175748)
		(width 0.088646)
		(layer "In4.Cu")
		(net "M_B_CPU1_SA_DQ<25>")
	)
	(segment
		(start 82.784188 -264.57402)
		(end 80.207104 -264.57402)
		(width 0.18288)
		(layer "In4.Cu")
		(net "M_B_CPU1_SA_DQ<25>")
	)
	(segment
		(start 48.354742 -286.141668)
		(end 47.389288 -286.141668)
		(width 0.18288)
		(layer "In4.Cu")
		(net "M_B_CPU1_SA_DQ<25>")
	)
	(arc
		(start 90.786204 -264.172446)
		(mid 90.601349 -264.125528)
		(end 90.417396 -264.175748)
		(width 0.088646)
		(layer "In4.Cu")
		(net "M_B_CPU1_SA_DQ<25>")
	)
	(arc
		(start 87.597996 -264.176002)
		(mid 87.315294 -264.251778)
		(end 87.032592 -264.176002)
		(width 0.088646)
		(layer "In4.Cu")
		(net "M_B_CPU1_SA_DQ<25>")
	)
	(arc
		(start 91.357196 -264.175748)
		(mid 91.078022 -264.251547)
		(end 90.797888 -264.179304)
		(width 0.088646)
		(layer "In4.Cu")
		(net "M_B_CPU1_SA_DQ<25>")
	)
	(arc
		(start 84.213192 -264.176002)
		(mid 84.025994 -264.125859)
		(end 83.838796 -264.176002)
		(width 0.088646)
		(layer "In4.Cu")
		(net "M_B_CPU1_SA_DQ<25>")
	)
	(arc
		(start 87.032592 -264.176002)
		(mid 86.845394 -264.125859)
		(end 86.658196 -264.176002)
		(width 0.088646)
		(layer "In4.Cu")
		(net "M_B_CPU1_SA_DQ<25>")
	)
	(arc
		(start 87.972392 -264.176002)
		(mid 87.785194 -264.125859)
		(end 87.597996 -264.176002)
		(width 0.088646)
		(layer "In4.Cu")
		(net "M_B_CPU1_SA_DQ<25>")
	)
	(arc
		(start 90.417396 -264.175748)
		(mid 90.136915 -264.25152)
		(end 89.855802 -264.178034)
		(width 0.088646)
		(layer "In4.Cu")
		(net "M_B_CPU1_SA_DQ<25>")
	)
	(arc
		(start 83.216242 -264.535412)
		(mid 83.146518 -264.564215)
		(end 83.071716 -264.57402)
		(width 0.088646)
		(layer "In4.Cu")
		(net "M_B_CPU1_SA_DQ<25>")
	)
	(arc
		(start 89.477596 -264.175748)
		(mid 89.197682 -264.251551)
		(end 88.917018 -264.178542)
		(width 0.088646)
		(layer "In4.Cu")
		(net "M_B_CPU1_SA_DQ<25>")
	)
	(arc
		(start 88.912192 -264.176002)
		(mid 88.724994 -264.125859)
		(end 88.537796 -264.176002)
		(width 0.088646)
		(layer "In4.Cu")
		(net "M_B_CPU1_SA_DQ<25>")
	)
	(arc
		(start 86.092792 -264.176002)
		(mid 85.905594 -264.125859)
		(end 85.718396 -264.176002)
		(width 0.088646)
		(layer "In4.Cu")
		(net "M_B_CPU1_SA_DQ<25>")
	)
	(arc
		(start 89.852246 -264.175748)
		(mid 89.664938 -264.125639)
		(end 89.477596 -264.175748)
		(width 0.088646)
		(layer "In4.Cu")
		(net "M_B_CPU1_SA_DQ<25>")
	)
	(arc
		(start 86.658196 -264.176002)
		(mid 86.375494 -264.251778)
		(end 86.092792 -264.176002)
		(width 0.088646)
		(layer "In4.Cu")
		(net "M_B_CPU1_SA_DQ<25>")
	)
	(arc
		(start 84.778596 -264.176002)
		(mid 84.495894 -264.251778)
		(end 84.213192 -264.176002)
		(width 0.088646)
		(layer "In4.Cu")
		(net "M_B_CPU1_SA_DQ<25>")
	)
	(arc
		(start 92.014548 -263.686544)
		(mid 91.74059 -263.926743)
		(end 91.437714 -264.129266)
		(width 0.088646)
		(layer "In4.Cu")
		(net "M_B_CPU1_SA_DQ<25>")
	)
	(arc
		(start 88.537796 -264.176002)
		(mid 88.255094 -264.251778)
		(end 87.972392 -264.176002)
		(width 0.088646)
		(layer "In4.Cu")
		(net "M_B_CPU1_SA_DQ<25>")
	)
	(arc
		(start 85.718396 -264.176002)
		(mid 85.435694 -264.251778)
		(end 85.152992 -264.176002)
		(width 0.088646)
		(layer "In4.Cu")
		(net "M_B_CPU1_SA_DQ<25>")
	)
	(arc
		(start 85.152992 -264.176002)
		(mid 84.965794 -264.125859)
		(end 84.778596 -264.176002)
		(width 0.088646)
		(layer "In4.Cu")
		(net "M_B_CPU1_SA_DQ<25>")
	)
	(segment
		(start 46.964346 -288.266632)
		(end 45.859446 -288.266632)
		(width 0.20066)
		(layer "F.Cu")
		(net "M_B_CPU1_SA_DQ<24>")
	)
	(segment
		(start 43.616626 -287.84169)
		(end 41.547542 -287.84169)
		(width 0.1016)
		(layer "F.Cu")
		(net "M_B_CPU1_SA_DQ<24>")
	)
	(segment
		(start 40.347392 -288.505392)
		(end 39.888668 -288.505392)
		(width 0.20066)
		(layer "F.Cu")
		(net "M_B_CPU1_SA_DQ<24>")
	)
	(segment
		(start 39.888668 -288.505392)
		(end 39.649908 -288.266632)
		(width 0.20066)
		(layer "F.Cu")
		(net "M_B_CPU1_SA_DQ<24>")
	)
	(segment
		(start 40.520112 -288.332672)
		(end 40.347392 -288.505392)
		(width 0.20066)
		(layer "F.Cu")
		(net "M_B_CPU1_SA_DQ<24>")
	)
	(segment
		(start 44.065444 -287.84169)
		(end 43.616626 -287.84169)
		(width 0.20066)
		(layer "F.Cu")
		(net "M_B_CPU1_SA_DQ<24>")
	)
	(segment
		(start 41.547542 -287.84169)
		(end 41.299638 -287.84169)
		(width 0.101854)
		(layer "F.Cu")
		(net "M_B_CPU1_SA_DQ<24>")
	)
	(segment
		(start 41.299638 -287.84169)
		(end 41.29151 -287.833562)
		(width 0.101854)
		(layer "F.Cu")
		(net "M_B_CPU1_SA_DQ<24>")
	)
	(segment
		(start 39.649908 -288.266632)
		(end 38.315646 -288.266632)
		(width 0.20066)
		(layer "F.Cu")
		(net "M_B_CPU1_SA_DQ<24>")
	)
	(segment
		(start 41.29151 -287.833562)
		(end 40.729662 -287.833562)
		(width 0.20066)
		(layer "F.Cu")
		(net "M_B_CPU1_SA_DQ<24>")
	)
	(segment
		(start 44.490386 -288.266632)
		(end 44.065444 -287.84169)
		(width 0.20066)
		(layer "F.Cu")
		(net "M_B_CPU1_SA_DQ<24>")
	)
	(segment
		(start 92.484448 -263.96442)
		(end 92.484194 -263.964674)
		(width 0.20066)
		(layer "F.Cu")
		(net "M_B_CPU1_SA_DQ<24>")
	)
	(segment
		(start 40.520112 -288.043112)
		(end 40.520112 -288.332672)
		(width 0.20066)
		(layer "F.Cu")
		(net "M_B_CPU1_SA_DQ<24>")
	)
	(segment
		(start 92.484194 -263.964674)
		(end 92.484194 -264.50036)
		(width 0.20066)
		(layer "F.Cu")
		(net "M_B_CPU1_SA_DQ<24>")
	)
	(segment
		(start 40.729662 -287.833562)
		(end 40.520112 -288.043112)
		(width 0.20066)
		(layer "F.Cu")
		(net "M_B_CPU1_SA_DQ<24>")
	)
	(segment
		(start 45.859446 -288.266632)
		(end 44.490386 -288.266632)
		(width 0.20066)
		(layer "F.Cu")
		(net "M_B_CPU1_SA_DQ<24>")
	)
	(segment
		(start 55.509668 -285.411164)
		(end 54.647846 -286.272986)
		(width 0.18288)
		(layer "In4.Cu")
		(net "M_B_CPU1_SA_DQ<24>")
	)
	(segment
		(start 61.080142 -282.618434)
		(end 59.821318 -283.877258)
		(width 0.18288)
		(layer "In4.Cu")
		(net "M_B_CPU1_SA_DQ<24>")
	)
	(segment
		(start 56.500522 -285.411164)
		(end 55.509668 -285.411164)
		(width 0.18288)
		(layer "In4.Cu")
		(net "M_B_CPU1_SA_DQ<24>")
	)
	(segment
		(start 83.138772 -265.07186)
		(end 82.784188 -265.07186)
		(width 0.088646)
		(layer "In4.Cu")
		(net "M_B_CPU1_SA_DQ<24>")
	)
	(segment
		(start 82.784188 -265.07186)
		(end 80.335882 -265.07186)
		(width 0.18288)
		(layer "In4.Cu")
		(net "M_B_CPU1_SA_DQ<24>")
	)
	(segment
		(start 47.56658 -287.20288)
		(end 47.56658 -287.664398)
		(width 0.18288)
		(layer "In4.Cu")
		(net "M_B_CPU1_SA_DQ<24>")
	)
	(segment
		(start 79.307182 -265.498072)
		(end 67.313048 -277.492206)
		(width 0.18288)
		(layer "In4.Cu")
		(net "M_B_CPU1_SA_DQ<24>")
	)
	(segment
		(start 64.061086 -281.194002)
		(end 62.636654 -282.618434)
		(width 0.18288)
		(layer "In4.Cu")
		(net "M_B_CPU1_SA_DQ<24>")
	)
	(segment
		(start 92.114878 -264.600436)
		(end 91.731846 -264.824718)
		(width 0.088646)
		(layer "In4.Cu")
		(net "M_B_CPU1_SA_DQ<24>")
	)
	(segment
		(start 53.66385 -286.272986)
		(end 53.343302 -286.593534)
		(width 0.18288)
		(layer "In4.Cu")
		(net "M_B_CPU1_SA_DQ<24>")
	)
	(segment
		(start 62.636654 -282.618434)
		(end 61.080142 -282.618434)
		(width 0.18288)
		(layer "In4.Cu")
		(net "M_B_CPU1_SA_DQ<24>")
	)
	(segment
		(start 47.777908 -286.991552)
		(end 47.56658 -287.20288)
		(width 0.18288)
		(layer "In4.Cu")
		(net "M_B_CPU1_SA_DQ<24>")
	)
	(segment
		(start 53.343302 -286.593534)
		(end 51.649122 -286.593534)
		(width 0.18288)
		(layer "In4.Cu")
		(net "M_B_CPU1_SA_DQ<24>")
	)
	(segment
		(start 51.649122 -286.593534)
		(end 51.251104 -286.991552)
		(width 0.18288)
		(layer "In4.Cu")
		(net "M_B_CPU1_SA_DQ<24>")
	)
	(segment
		(start 80.335882 -265.07186)
		(end 79.307182 -265.498072)
		(width 0.18288)
		(layer "In4.Cu")
		(net "M_B_CPU1_SA_DQ<24>")
	)
	(segment
		(start 65.27292 -280.54808)
		(end 64.061086 -281.194002)
		(width 0.18288)
		(layer "In4.Cu")
		(net "M_B_CPU1_SA_DQ<24>")
	)
	(segment
		(start 83.461606 -264.749026)
		(end 83.138772 -265.07186)
		(width 0.088646)
		(layer "In4.Cu")
		(net "M_B_CPU1_SA_DQ<24>")
	)
	(segment
		(start 54.647846 -286.272986)
		(end 53.66385 -286.272986)
		(width 0.18288)
		(layer "In4.Cu")
		(net "M_B_CPU1_SA_DQ<24>")
	)
	(segment
		(start 58.034428 -283.877258)
		(end 56.500522 -285.411164)
		(width 0.18288)
		(layer "In4.Cu")
		(net "M_B_CPU1_SA_DQ<24>")
	)
	(segment
		(start 59.821318 -283.877258)
		(end 58.034428 -283.877258)
		(width 0.18288)
		(layer "In4.Cu")
		(net "M_B_CPU1_SA_DQ<24>")
	)
	(segment
		(start 66.594736 -279.226264)
		(end 65.27292 -280.54808)
		(width 0.18288)
		(layer "In4.Cu")
		(net "M_B_CPU1_SA_DQ<24>")
	)
	(segment
		(start 91.35745 -264.824718)
		(end 91.347036 -264.818622)
		(width 0.088646)
		(layer "In4.Cu")
		(net "M_B_CPU1_SA_DQ<24>")
	)
	(segment
		(start 83.556094 -264.749026)
		(end 83.461606 -264.749026)
		(width 0.088646)
		(layer "In4.Cu")
		(net "M_B_CPU1_SA_DQ<24>")
	)
	(segment
		(start 47.56658 -287.664398)
		(end 46.964346 -288.266632)
		(width 0.18288)
		(layer "In4.Cu")
		(net "M_B_CPU1_SA_DQ<24>")
	)
	(segment
		(start 51.251104 -286.991552)
		(end 47.777908 -286.991552)
		(width 0.18288)
		(layer "In4.Cu")
		(net "M_B_CPU1_SA_DQ<24>")
	)
	(segment
		(start 67.313048 -277.492206)
		(end 66.594736 -279.226264)
		(width 0.18288)
		(layer "In4.Cu")
		(net "M_B_CPU1_SA_DQ<24>")
	)
	(arc
		(start 91.347036 -264.818622)
		(mid 91.068604 -264.748776)
		(end 90.791792 -264.824718)
		(width 0.088646)
		(layer "In4.Cu")
		(net "M_B_CPU1_SA_DQ<24>")
	)
	(arc
		(start 91.731846 -264.824718)
		(mid 91.544648 -264.874861)
		(end 91.35745 -264.824718)
		(width 0.088646)
		(layer "In4.Cu")
		(net "M_B_CPU1_SA_DQ<24>")
	)
	(arc
		(start 87.032592 -264.824718)
		(mid 86.845394 -264.874861)
		(end 86.658196 -264.824718)
		(width 0.088646)
		(layer "In4.Cu")
		(net "M_B_CPU1_SA_DQ<24>")
	)
	(arc
		(start 86.658196 -264.824718)
		(mid 86.375494 -264.748942)
		(end 86.092792 -264.824718)
		(width 0.088646)
		(layer "In4.Cu")
		(net "M_B_CPU1_SA_DQ<24>")
	)
	(arc
		(start 92.484194 -264.50036)
		(mid 92.292885 -264.525837)
		(end 92.114878 -264.600436)
		(width 0.088646)
		(layer "In4.Cu")
		(net "M_B_CPU1_SA_DQ<24>")
	)
	(arc
		(start 86.092792 -264.824718)
		(mid 85.905594 -264.874861)
		(end 85.718396 -264.824718)
		(width 0.088646)
		(layer "In4.Cu")
		(net "M_B_CPU1_SA_DQ<24>")
	)
	(arc
		(start 88.537796 -264.824718)
		(mid 88.255094 -264.748942)
		(end 87.972392 -264.824718)
		(width 0.088646)
		(layer "In4.Cu")
		(net "M_B_CPU1_SA_DQ<24>")
	)
	(arc
		(start 84.778596 -264.824718)
		(mid 84.495894 -264.748942)
		(end 84.213192 -264.824718)
		(width 0.088646)
		(layer "In4.Cu")
		(net "M_B_CPU1_SA_DQ<24>")
	)
	(arc
		(start 85.152992 -264.824718)
		(mid 84.965794 -264.874861)
		(end 84.778596 -264.824718)
		(width 0.088646)
		(layer "In4.Cu")
		(net "M_B_CPU1_SA_DQ<24>")
	)
	(arc
		(start 90.791792 -264.824718)
		(mid 90.604594 -264.874861)
		(end 90.417396 -264.824718)
		(width 0.088646)
		(layer "In4.Cu")
		(net "M_B_CPU1_SA_DQ<24>")
	)
	(arc
		(start 89.477596 -264.824718)
		(mid 89.194894 -264.748942)
		(end 88.912192 -264.824718)
		(width 0.088646)
		(layer "In4.Cu")
		(net "M_B_CPU1_SA_DQ<24>")
	)
	(arc
		(start 83.838796 -264.824718)
		(mid 83.702427 -264.768276)
		(end 83.556094 -264.749026)
		(width 0.088646)
		(layer "In4.Cu")
		(net "M_B_CPU1_SA_DQ<24>")
	)
	(arc
		(start 88.912192 -264.824718)
		(mid 88.724994 -264.874861)
		(end 88.537796 -264.824718)
		(width 0.088646)
		(layer "In4.Cu")
		(net "M_B_CPU1_SA_DQ<24>")
	)
	(arc
		(start 89.851992 -264.824718)
		(mid 89.664794 -264.874861)
		(end 89.477596 -264.824718)
		(width 0.088646)
		(layer "In4.Cu")
		(net "M_B_CPU1_SA_DQ<24>")
	)
	(arc
		(start 87.972392 -264.824718)
		(mid 87.785194 -264.874861)
		(end 87.597996 -264.824718)
		(width 0.088646)
		(layer "In4.Cu")
		(net "M_B_CPU1_SA_DQ<24>")
	)
	(arc
		(start 84.213192 -264.824718)
		(mid 84.025994 -264.874861)
		(end 83.838796 -264.824718)
		(width 0.088646)
		(layer "In4.Cu")
		(net "M_B_CPU1_SA_DQ<24>")
	)
	(arc
		(start 87.597996 -264.824718)
		(mid 87.315294 -264.748942)
		(end 87.032592 -264.824718)
		(width 0.088646)
		(layer "In4.Cu")
		(net "M_B_CPU1_SA_DQ<24>")
	)
	(arc
		(start 90.417396 -264.824718)
		(mid 90.134694 -264.748942)
		(end 89.851992 -264.824718)
		(width 0.088646)
		(layer "In4.Cu")
		(net "M_B_CPU1_SA_DQ<24>")
	)
	(arc
		(start 85.718396 -264.824718)
		(mid 85.435694 -264.748942)
		(end 85.152992 -264.824718)
		(width 0.088646)
		(layer "In4.Cu")
		(net "M_B_CPU1_SA_DQ<24>")
	)
	(segment
		(start 49.143412 -289.11677)
		(end 48.935894 -289.324288)
		(width 0.20066)
		(layer "F.Cu")
		(net "M_B_CPU1_SA_DQ<23>")
	)
	(segment
		(start 90.134694 -263.150604)
		(end 90.134694 -263.686544)
		(width 0.20066)
		(layer "F.Cu")
		(net "M_B_CPU1_SA_DQ<23>")
	)
	(segment
		(start 44.38142 -289.555936)
		(end 44.238926 -289.413442)
		(width 0.20066)
		(layer "F.Cu")
		(net "M_B_CPU1_SA_DQ<23>")
	)
	(segment
		(start 47.882302 -289.112452)
		(end 47.753778 -289.240976)
		(width 0.20066)
		(layer "F.Cu")
		(net "M_B_CPU1_SA_DQ<23>")
	)
	(segment
		(start 44.987464 -289.541712)
		(end 44.749466 -289.541712)
		(width 0.101854)
		(layer "F.Cu")
		(net "M_B_CPU1_SA_DQ<23>")
	)
	(segment
		(start 44.735242 -289.555936)
		(end 44.38142 -289.555936)
		(width 0.20066)
		(layer "F.Cu")
		(net "M_B_CPU1_SA_DQ<23>")
	)
	(segment
		(start 47.753778 -289.240976)
		(end 47.753778 -289.392614)
		(width 0.20066)
		(layer "F.Cu")
		(net "M_B_CPU1_SA_DQ<23>")
	)
	(segment
		(start 44.238926 -289.413442)
		(end 44.238926 -289.242754)
		(width 0.20066)
		(layer "F.Cu")
		(net "M_B_CPU1_SA_DQ<23>")
	)
	(segment
		(start 44.238926 -289.242754)
		(end 44.112942 -289.11677)
		(width 0.20066)
		(layer "F.Cu")
		(net "M_B_CPU1_SA_DQ<23>")
	)
	(segment
		(start 48.935894 -289.324288)
		(end 48.489362 -289.324288)
		(width 0.20066)
		(layer "F.Cu")
		(net "M_B_CPU1_SA_DQ<23>")
	)
	(segment
		(start 48.277526 -289.112452)
		(end 47.882302 -289.112452)
		(width 0.20066)
		(layer "F.Cu")
		(net "M_B_CPU1_SA_DQ<23>")
	)
	(segment
		(start 47.753778 -289.392614)
		(end 47.60468 -289.541712)
		(width 0.20066)
		(layer "F.Cu")
		(net "M_B_CPU1_SA_DQ<23>")
	)
	(segment
		(start 51.089814 -289.11677)
		(end 49.959514 -289.11677)
		(width 0.20066)
		(layer "F.Cu")
		(net "M_B_CPU1_SA_DQ<23>")
	)
	(segment
		(start 48.489362 -289.324288)
		(end 48.277526 -289.112452)
		(width 0.20066)
		(layer "F.Cu")
		(net "M_B_CPU1_SA_DQ<23>")
	)
	(segment
		(start 44.112942 -289.11677)
		(end 42.415714 -289.11677)
		(width 0.20066)
		(layer "F.Cu")
		(net "M_B_CPU1_SA_DQ<23>")
	)
	(segment
		(start 44.749466 -289.541712)
		(end 44.735242 -289.555936)
		(width 0.101854)
		(layer "F.Cu")
		(net "M_B_CPU1_SA_DQ<23>")
	)
	(segment
		(start 49.959514 -289.11677)
		(end 49.143412 -289.11677)
		(width 0.20066)
		(layer "F.Cu")
		(net "M_B_CPU1_SA_DQ<23>")
	)
	(segment
		(start 47.60468 -289.541712)
		(end 47.060358 -289.541712)
		(width 0.20066)
		(layer "F.Cu")
		(net "M_B_CPU1_SA_DQ<23>")
	)
	(segment
		(start 47.060358 -289.541712)
		(end 44.987464 -289.541712)
		(width 0.1016)
		(layer "F.Cu")
		(net "M_B_CPU1_SA_DQ<23>")
	)
	(segment
		(start 89.821766 -263.686544)
		(end 89.756742 -263.62152)
		(width 0.088646)
		(layer "In2.Cu")
		(net "M_B_CPU1_SA_DQ<23>")
	)
	(segment
		(start 79.454248 -266.941808)
		(end 76.8477 -268.021308)
		(width 0.18288)
		(layer "In2.Cu")
		(net "M_B_CPU1_SA_DQ<23>")
	)
	(segment
		(start 57.927494 -281.084274)
		(end 57.767474 -280.924254)
		(width 0.18288)
		(layer "In2.Cu")
		(net "M_B_CPU1_SA_DQ<23>")
	)
	(segment
		(start 53.957728 -282.895548)
		(end 52.653184 -282.895548)
		(width 0.18288)
		(layer "In2.Cu")
		(net "M_B_CPU1_SA_DQ<23>")
	)
	(segment
		(start 57.607454 -280.214832)
		(end 57.145936 -280.214832)
		(width 0.18288)
		(layer "In2.Cu")
		(net "M_B_CPU1_SA_DQ<23>")
	)
	(segment
		(start 67.460876 -277.408132)
		(end 67.460876 -278.272494)
		(width 0.18288)
		(layer "In2.Cu")
		(net "M_B_CPU1_SA_DQ<23>")
	)
	(segment
		(start 57.767474 -280.374852)
		(end 57.607454 -280.214832)
		(width 0.18288)
		(layer "In2.Cu")
		(net "M_B_CPU1_SA_DQ<23>")
	)
	(segment
		(start 51.748182 -282.921202)
		(end 51.748182 -285.899352)
		(width 0.18288)
		(layer "In2.Cu")
		(net "M_B_CPU1_SA_DQ<23>")
	)
	(segment
		(start 55.299864 -281.806396)
		(end 55.255922 -282.028138)
		(width 0.18288)
		(layer "In2.Cu")
		(net "M_B_CPU1_SA_DQ<23>")
	)
	(segment
		(start 49.007268 -287.687258)
		(end 49.944782 -288.624772)
		(width 0.18288)
		(layer "In2.Cu")
		(net "M_B_CPU1_SA_DQ<23>")
	)
	(segment
		(start 62.855602 -280.214832)
		(end 59.636914 -280.214832)
		(width 0.18288)
		(layer "In2.Cu")
		(net "M_B_CPU1_SA_DQ<23>")
	)
	(segment
		(start 56.952896 -280.407872)
		(end 56.952896 -280.774394)
		(width 0.18288)
		(layer "In2.Cu")
		(net "M_B_CPU1_SA_DQ<23>")
	)
	(segment
		(start 55.074312 -281.468576)
		(end 55.299864 -281.806396)
		(width 0.18288)
		(layer "In2.Cu")
		(net "M_B_CPU1_SA_DQ<23>")
	)
	(segment
		(start 51.089814 -288.836862)
		(end 51.089814 -289.11677)
		(width 0.18288)
		(layer "In2.Cu")
		(net "M_B_CPU1_SA_DQ<23>")
	)
	(segment
		(start 55.650892 -281.083258)
		(end 55.42915 -281.039062)
		(width 0.18288)
		(layer "In2.Cu")
		(net "M_B_CPU1_SA_DQ<23>")
	)
	(segment
		(start 81.667604 -265.304524)
		(end 81.091532 -265.304524)
		(width 0.088646)
		(layer "In2.Cu")
		(net "M_B_CPU1_SA_DQ<23>")
	)
	(segment
		(start 56.098186 -281.465274)
		(end 55.876698 -281.421078)
		(width 0.18288)
		(layer "In2.Cu")
		(net "M_B_CPU1_SA_DQ<23>")
	)
	(segment
		(start 80.998822 -265.397234)
		(end 79.454248 -266.941808)
		(width 0.18288)
		(layer "In2.Cu")
		(net "M_B_CPU1_SA_DQ<23>")
	)
	(segment
		(start 55.876698 -281.421078)
		(end 55.650892 -281.083258)
		(width 0.18288)
		(layer "In2.Cu")
		(net "M_B_CPU1_SA_DQ<23>")
	)
	(segment
		(start 67.460876 -278.272494)
		(end 66.387218 -279.346152)
		(width 0.18288)
		(layer "In2.Cu")
		(net "M_B_CPU1_SA_DQ<23>")
	)
	(segment
		(start 90.134694 -263.686544)
		(end 89.821766 -263.686544)
		(width 0.088646)
		(layer "In2.Cu")
		(net "M_B_CPU1_SA_DQ<23>")
	)
	(segment
		(start 83.838796 -263.196832)
		(end 83.775296 -263.196832)
		(width 0.088646)
		(layer "In2.Cu")
		(net "M_B_CPU1_SA_DQ<23>")
	)
	(segment
		(start 56.952896 -280.774394)
		(end 56.591962 -281.135328)
		(width 0.18288)
		(layer "In2.Cu")
		(net "M_B_CPU1_SA_DQ<23>")
	)
	(segment
		(start 52.485798 -282.728162)
		(end 51.941222 -282.728162)
		(width 0.18288)
		(layer "In2.Cu")
		(net "M_B_CPU1_SA_DQ<23>")
	)
	(segment
		(start 51.748182 -285.899352)
		(end 51.505866 -286.141668)
		(width 0.18288)
		(layer "In2.Cu")
		(net "M_B_CPU1_SA_DQ<23>")
	)
	(segment
		(start 58.767472 -281.084274)
		(end 57.927494 -281.084274)
		(width 0.18288)
		(layer "In2.Cu")
		(net "M_B_CPU1_SA_DQ<23>")
	)
	(segment
		(start 55.118254 -281.246834)
		(end 55.074312 -281.468576)
		(width 0.18288)
		(layer "In2.Cu")
		(net "M_B_CPU1_SA_DQ<23>")
	)
	(segment
		(start 51.941222 -282.728162)
		(end 51.748182 -282.921202)
		(width 0.18288)
		(layer "In2.Cu")
		(net "M_B_CPU1_SA_DQ<23>")
	)
	(segment
		(start 55.255922 -282.028138)
		(end 53.957728 -282.895548)
		(width 0.18288)
		(layer "In2.Cu")
		(net "M_B_CPU1_SA_DQ<23>")
	)
	(segment
		(start 52.653184 -282.895548)
		(end 52.485798 -282.728162)
		(width 0.18288)
		(layer "In2.Cu")
		(net "M_B_CPU1_SA_DQ<23>")
	)
	(segment
		(start 76.8477 -268.021308)
		(end 67.460876 -277.408132)
		(width 0.18288)
		(layer "In2.Cu")
		(net "M_B_CPU1_SA_DQ<23>")
	)
	(segment
		(start 81.091532 -265.304524)
		(end 80.998822 -265.397234)
		(width 0.088646)
		(layer "In2.Cu")
		(net "M_B_CPU1_SA_DQ<23>")
	)
	(segment
		(start 83.775296 -263.196832)
		(end 81.667604 -265.304524)
		(width 0.088646)
		(layer "In2.Cu")
		(net "M_B_CPU1_SA_DQ<23>")
	)
	(segment
		(start 49.944782 -288.624772)
		(end 50.728626 -288.624772)
		(width 0.18288)
		(layer "In2.Cu")
		(net "M_B_CPU1_SA_DQ<23>")
	)
	(segment
		(start 50.728626 -288.624772)
		(end 50.983134 -288.730182)
		(width 0.18288)
		(layer "In2.Cu")
		(net "M_B_CPU1_SA_DQ<23>")
	)
	(segment
		(start 51.505866 -286.141668)
		(end 49.977294 -286.141668)
		(width 0.18288)
		(layer "In2.Cu")
		(net "M_B_CPU1_SA_DQ<23>")
	)
	(segment
		(start 59.636914 -280.214832)
		(end 58.767472 -281.084274)
		(width 0.18288)
		(layer "In2.Cu")
		(net "M_B_CPU1_SA_DQ<23>")
	)
	(segment
		(start 66.387218 -279.346152)
		(end 63.724282 -279.346152)
		(width 0.18288)
		(layer "In2.Cu")
		(net "M_B_CPU1_SA_DQ<23>")
	)
	(segment
		(start 85.152992 -263.196832)
		(end 85.152992 -263.197086)
		(width 0.088646)
		(layer "In2.Cu")
		(net "M_B_CPU1_SA_DQ<23>")
	)
	(segment
		(start 84.213192 -263.197086)
		(end 84.213192 -263.196832)
		(width 0.088646)
		(layer "In2.Cu")
		(net "M_B_CPU1_SA_DQ<23>")
	)
	(segment
		(start 63.724282 -279.346152)
		(end 62.855602 -280.214832)
		(width 0.18288)
		(layer "In2.Cu")
		(net "M_B_CPU1_SA_DQ<23>")
	)
	(segment
		(start 57.145936 -280.214832)
		(end 56.952896 -280.407872)
		(width 0.18288)
		(layer "In2.Cu")
		(net "M_B_CPU1_SA_DQ<23>")
	)
	(segment
		(start 56.591962 -281.135328)
		(end 56.098186 -281.465274)
		(width 0.18288)
		(layer "In2.Cu")
		(net "M_B_CPU1_SA_DQ<23>")
	)
	(segment
		(start 49.977294 -286.141668)
		(end 49.007268 -287.111694)
		(width 0.18288)
		(layer "In2.Cu")
		(net "M_B_CPU1_SA_DQ<23>")
	)
	(segment
		(start 49.007268 -287.111694)
		(end 49.007268 -287.687258)
		(width 0.18288)
		(layer "In2.Cu")
		(net "M_B_CPU1_SA_DQ<23>")
	)
	(segment
		(start 50.983134 -288.730182)
		(end 51.089814 -288.836862)
		(width 0.18288)
		(layer "In2.Cu")
		(net "M_B_CPU1_SA_DQ<23>")
	)
	(segment
		(start 55.42915 -281.039062)
		(end 55.118254 -281.246834)
		(width 0.18288)
		(layer "In2.Cu")
		(net "M_B_CPU1_SA_DQ<23>")
	)
	(segment
		(start 57.767474 -280.924254)
		(end 57.767474 -280.374852)
		(width 0.18288)
		(layer "In2.Cu")
		(net "M_B_CPU1_SA_DQ<23>")
	)
	(arc
		(start 88.912192 -263.196832)
		(mid 88.724994 -263.246975)
		(end 88.537796 -263.196832)
		(width 0.088646)
		(layer "In2.Cu")
		(net "M_B_CPU1_SA_DQ<23>")
	)
	(arc
		(start 85.152992 -263.197086)
		(mid 84.965794 -263.247229)
		(end 84.778596 -263.197086)
		(width 0.088646)
		(layer "In2.Cu")
		(net "M_B_CPU1_SA_DQ<23>")
	)
	(arc
		(start 86.092792 -263.196832)
		(mid 85.905594 -263.246975)
		(end 85.718396 -263.196832)
		(width 0.088646)
		(layer "In2.Cu")
		(net "M_B_CPU1_SA_DQ<23>")
	)
	(arc
		(start 84.778596 -263.197086)
		(mid 84.495894 -263.12131)
		(end 84.213192 -263.197086)
		(width 0.088646)
		(layer "In2.Cu")
		(net "M_B_CPU1_SA_DQ<23>")
	)
	(arc
		(start 85.718396 -263.196832)
		(mid 85.435694 -263.12109)
		(end 85.152992 -263.196832)
		(width 0.088646)
		(layer "In2.Cu")
		(net "M_B_CPU1_SA_DQ<23>")
	)
	(arc
		(start 87.032592 -263.196832)
		(mid 86.845394 -263.246975)
		(end 86.658196 -263.196832)
		(width 0.088646)
		(layer "In2.Cu")
		(net "M_B_CPU1_SA_DQ<23>")
	)
	(arc
		(start 84.213192 -263.196832)
		(mid 84.025994 -263.246975)
		(end 83.838796 -263.196832)
		(width 0.088646)
		(layer "In2.Cu")
		(net "M_B_CPU1_SA_DQ<23>")
	)
	(arc
		(start 87.972392 -263.196832)
		(mid 87.785194 -263.246975)
		(end 87.597996 -263.196832)
		(width 0.088646)
		(layer "In2.Cu")
		(net "M_B_CPU1_SA_DQ<23>")
	)
	(arc
		(start 87.597996 -263.196832)
		(mid 87.315294 -263.12109)
		(end 87.032592 -263.196832)
		(width 0.088646)
		(layer "In2.Cu")
		(net "M_B_CPU1_SA_DQ<23>")
	)
	(arc
		(start 88.537796 -263.196832)
		(mid 88.255094 -263.12109)
		(end 87.972392 -263.196832)
		(width 0.088646)
		(layer "In2.Cu")
		(net "M_B_CPU1_SA_DQ<23>")
	)
	(arc
		(start 89.756742 -263.62152)
		(mid 89.667588 -263.376033)
		(end 89.477596 -263.196832)
		(width 0.088646)
		(layer "In2.Cu")
		(net "M_B_CPU1_SA_DQ<23>")
	)
	(arc
		(start 89.477596 -263.196832)
		(mid 89.194894 -263.12109)
		(end 88.912192 -263.196832)
		(width 0.088646)
		(layer "In2.Cu")
		(net "M_B_CPU1_SA_DQ<23>")
	)
	(arc
		(start 86.658196 -263.196832)
		(mid 86.375494 -263.12109)
		(end 86.092792 -263.196832)
		(width 0.088646)
		(layer "In2.Cu")
		(net "M_B_CPU1_SA_DQ<23>")
	)
	(segment
		(start 48.432974 -291.028628)
		(end 48.004476 -291.028628)
		(width 0.20066)
		(layer "F.Cu")
		(net "M_B_CPU1_SA_DQ<22>")
	)
	(segment
		(start 49.959514 -290.816792)
		(end 48.64481 -290.816792)
		(width 0.20066)
		(layer "F.Cu")
		(net "M_B_CPU1_SA_DQ<22>")
	)
	(segment
		(start 43.562778 -290.816792)
		(end 42.415714 -290.816792)
		(width 0.20066)
		(layer "F.Cu")
		(net "M_B_CPU1_SA_DQ<22>")
	)
	(segment
		(start 48.004476 -291.028628)
		(end 47.83709 -290.861242)
		(width 0.20066)
		(layer "F.Cu")
		(net "M_B_CPU1_SA_DQ<22>")
	)
	(segment
		(start 90.604594 -263.964674)
		(end 90.604594 -264.50036)
		(width 0.20066)
		(layer "F.Cu")
		(net "M_B_CPU1_SA_DQ<22>")
	)
	(segment
		(start 44.735242 -290.38169)
		(end 43.99788 -290.38169)
		(width 0.20066)
		(layer "F.Cu")
		(net "M_B_CPU1_SA_DQ<22>")
	)
	(segment
		(start 47.83709 -290.535614)
		(end 47.693326 -290.39185)
		(width 0.20066)
		(layer "F.Cu")
		(net "M_B_CPU1_SA_DQ<22>")
	)
	(segment
		(start 44.745402 -290.39185)
		(end 44.735242 -290.38169)
		(width 0.101854)
		(layer "F.Cu")
		(net "M_B_CPU1_SA_DQ<22>")
	)
	(segment
		(start 48.64481 -290.816792)
		(end 48.432974 -291.028628)
		(width 0.20066)
		(layer "F.Cu")
		(net "M_B_CPU1_SA_DQ<22>")
	)
	(segment
		(start 43.99788 -290.38169)
		(end 43.562778 -290.816792)
		(width 0.20066)
		(layer "F.Cu")
		(net "M_B_CPU1_SA_DQ<22>")
	)
	(segment
		(start 47.83709 -290.861242)
		(end 47.83709 -290.535614)
		(width 0.20066)
		(layer "F.Cu")
		(net "M_B_CPU1_SA_DQ<22>")
	)
	(segment
		(start 47.693326 -290.39185)
		(end 47.060358 -290.39185)
		(width 0.20066)
		(layer "F.Cu")
		(net "M_B_CPU1_SA_DQ<22>")
	)
	(segment
		(start 47.060358 -290.39185)
		(end 45.000418 -290.39185)
		(width 0.1016)
		(layer "F.Cu")
		(net "M_B_CPU1_SA_DQ<22>")
	)
	(segment
		(start 45.000418 -290.39185)
		(end 44.745402 -290.39185)
		(width 0.101854)
		(layer "F.Cu")
		(net "M_B_CPU1_SA_DQ<22>")
	)
	(segment
		(start 51.089814 -290.816792)
		(end 49.959514 -290.816792)
		(width 0.20066)
		(layer "F.Cu")
		(net "M_B_CPU1_SA_DQ<22>")
	)
	(segment
		(start 90.604848 -263.96442)
		(end 90.604594 -263.964674)
		(width 0.20066)
		(layer "F.Cu")
		(net "M_B_CPU1_SA_DQ<22>")
	)
	(segment
		(start 64.551052 -280.683462)
		(end 63.936372 -281.298142)
		(width 0.18288)
		(layer "In2.Cu")
		(net "M_B_CPU1_SA_DQ<22>")
	)
	(segment
		(start 55.431182 -284.916372)
		(end 55.253382 -285.094172)
		(width 0.18288)
		(layer "In2.Cu")
		(net "M_B_CPU1_SA_DQ<22>")
	)
	(segment
		(start 53.83276 -289.539172)
		(end 52.367434 -289.539172)
		(width 0.18288)
		(layer "In2.Cu")
		(net "M_B_CPU1_SA_DQ<22>")
	)
	(segment
		(start 53.779166 -288.68751)
		(end 54.065424 -288.973768)
		(width 0.18288)
		(layer "In2.Cu")
		(net "M_B_CPU1_SA_DQ<22>")
	)
	(segment
		(start 90.29192 -264.50036)
		(end 90.226388 -264.434828)
		(width 0.088646)
		(layer "In2.Cu")
		(net "M_B_CPU1_SA_DQ<22>")
	)
	(segment
		(start 60.607702 -281.65298)
		(end 60.34151 -281.919172)
		(width 0.18288)
		(layer "In2.Cu")
		(net "M_B_CPU1_SA_DQ<22>")
	)
	(segment
		(start 81.623662 -265.75258)
		(end 81.505806 -265.870436)
		(width 0.088646)
		(layer "In2.Cu")
		(net "M_B_CPU1_SA_DQ<22>")
	)
	(segment
		(start 53.653182 -287.583372)
		(end 52.750974 -287.583372)
		(width 0.18288)
		(layer "In2.Cu")
		(net "M_B_CPU1_SA_DQ<22>")
	)
	(segment
		(start 54.338982 -286.186372)
		(end 54.338982 -286.897572)
		(width 0.18288)
		(layer "In2.Cu")
		(net "M_B_CPU1_SA_DQ<22>")
	)
	(segment
		(start 56.65089 -283.620972)
		(end 56.226202 -284.04566)
		(width 0.18288)
		(layer "In2.Cu")
		(net "M_B_CPU1_SA_DQ<22>")
	)
	(segment
		(start 54.04739 -285.89478)
		(end 54.338982 -286.186372)
		(width 0.18288)
		(layer "In2.Cu")
		(net "M_B_CPU1_SA_DQ<22>")
	)
	(segment
		(start 56.226202 -284.04566)
		(end 55.986934 -284.04566)
		(width 0.18288)
		(layer "In2.Cu")
		(net "M_B_CPU1_SA_DQ<22>")
	)
	(segment
		(start 55.856124 -283.91485)
		(end 55.62981 -283.91485)
		(width 0.18288)
		(layer "In2.Cu")
		(net "M_B_CPU1_SA_DQ<22>")
	)
	(segment
		(start 65.482724 -280.683462)
		(end 64.551052 -280.683462)
		(width 0.18288)
		(layer "In2.Cu")
		(net "M_B_CPU1_SA_DQ<22>")
	)
	(segment
		(start 62.343538 -281.919172)
		(end 61.275722 -281.919172)
		(width 0.18288)
		(layer "In2.Cu")
		(net "M_B_CPU1_SA_DQ<22>")
	)
	(segment
		(start 83.539838 -264.136378)
		(end 81.923636 -265.75258)
		(width 0.088646)
		(layer "In2.Cu")
		(net "M_B_CPU1_SA_DQ<22>")
	)
	(segment
		(start 55.255668 -284.288992)
		(end 55.255668 -284.514798)
		(width 0.18288)
		(layer "In2.Cu")
		(net "M_B_CPU1_SA_DQ<22>")
	)
	(segment
		(start 54.065424 -289.306508)
		(end 53.83276 -289.539172)
		(width 0.18288)
		(layer "In2.Cu")
		(net "M_B_CPU1_SA_DQ<22>")
	)
	(segment
		(start 54.065424 -288.973768)
		(end 54.065424 -289.306508)
		(width 0.18288)
		(layer "In2.Cu")
		(net "M_B_CPU1_SA_DQ<22>")
	)
	(segment
		(start 54.338982 -286.897572)
		(end 53.653182 -287.583372)
		(width 0.18288)
		(layer "In2.Cu")
		(net "M_B_CPU1_SA_DQ<22>")
	)
	(segment
		(start 52.750974 -287.583372)
		(end 52.35956 -287.974786)
		(width 0.18288)
		(layer "In2.Cu")
		(net "M_B_CPU1_SA_DQ<22>")
	)
	(segment
		(start 63.936372 -281.298142)
		(end 62.964568 -281.298142)
		(width 0.18288)
		(layer "In2.Cu")
		(net "M_B_CPU1_SA_DQ<22>")
	)
	(segment
		(start 55.431182 -284.690312)
		(end 55.431182 -284.916372)
		(width 0.18288)
		(layer "In2.Cu")
		(net "M_B_CPU1_SA_DQ<22>")
	)
	(segment
		(start 52.35956 -287.974786)
		(end 52.35956 -288.516314)
		(width 0.18288)
		(layer "In2.Cu")
		(net "M_B_CPU1_SA_DQ<22>")
	)
	(segment
		(start 58.656982 -283.214572)
		(end 58.250582 -283.620972)
		(width 0.18288)
		(layer "In2.Cu")
		(net "M_B_CPU1_SA_DQ<22>")
	)
	(segment
		(start 61.00953 -281.65298)
		(end 60.607702 -281.65298)
		(width 0.18288)
		(layer "In2.Cu")
		(net "M_B_CPU1_SA_DQ<22>")
	)
	(segment
		(start 61.275722 -281.919172)
		(end 61.00953 -281.65298)
		(width 0.18288)
		(layer "In2.Cu")
		(net "M_B_CPU1_SA_DQ<22>")
	)
	(segment
		(start 54.04739 -285.518352)
		(end 54.04739 -285.89478)
		(width 0.18288)
		(layer "In2.Cu")
		(net "M_B_CPU1_SA_DQ<22>")
	)
	(segment
		(start 68.54825 -277.80869)
		(end 68.54825 -278.891492)
		(width 0.18288)
		(layer "In2.Cu")
		(net "M_B_CPU1_SA_DQ<22>")
	)
	(segment
		(start 55.62981 -283.91485)
		(end 55.255668 -284.288992)
		(width 0.18288)
		(layer "In2.Cu")
		(net "M_B_CPU1_SA_DQ<22>")
	)
	(segment
		(start 54.47157 -285.094172)
		(end 54.04739 -285.518352)
		(width 0.18288)
		(layer "In2.Cu")
		(net "M_B_CPU1_SA_DQ<22>")
	)
	(segment
		(start 55.986934 -284.04566)
		(end 55.856124 -283.91485)
		(width 0.18288)
		(layer "In2.Cu")
		(net "M_B_CPU1_SA_DQ<22>")
	)
	(segment
		(start 68.54825 -278.891492)
		(end 66.300858 -281.140154)
		(width 0.18288)
		(layer "In2.Cu")
		(net "M_B_CPU1_SA_DQ<22>")
	)
	(segment
		(start 81.923636 -265.75258)
		(end 81.623662 -265.75258)
		(width 0.088646)
		(layer "In2.Cu")
		(net "M_B_CPU1_SA_DQ<22>")
	)
	(segment
		(start 58.656982 -282.935172)
		(end 58.656982 -283.214572)
		(width 0.18288)
		(layer "In2.Cu")
		(net "M_B_CPU1_SA_DQ<22>")
	)
	(segment
		(start 55.253382 -285.094172)
		(end 54.47157 -285.094172)
		(width 0.18288)
		(layer "In2.Cu")
		(net "M_B_CPU1_SA_DQ<22>")
	)
	(segment
		(start 52.367434 -289.539172)
		(end 51.089814 -290.816792)
		(width 0.18288)
		(layer "In2.Cu")
		(net "M_B_CPU1_SA_DQ<22>")
	)
	(segment
		(start 81.505806 -265.870436)
		(end 79.713074 -267.66393)
		(width 0.18288)
		(layer "In2.Cu")
		(net "M_B_CPU1_SA_DQ<22>")
	)
	(segment
		(start 90.604594 -264.50036)
		(end 90.29192 -264.50036)
		(width 0.088646)
		(layer "In2.Cu")
		(net "M_B_CPU1_SA_DQ<22>")
	)
	(segment
		(start 77.965554 -268.388084)
		(end 77.474572 -268.87932)
		(width 0.18288)
		(layer "In2.Cu")
		(net "M_B_CPU1_SA_DQ<22>")
	)
	(segment
		(start 52.35956 -288.516314)
		(end 52.530756 -288.68751)
		(width 0.18288)
		(layer "In2.Cu")
		(net "M_B_CPU1_SA_DQ<22>")
	)
	(segment
		(start 52.530756 -288.68751)
		(end 53.779166 -288.68751)
		(width 0.18288)
		(layer "In2.Cu")
		(net "M_B_CPU1_SA_DQ<22>")
	)
	(segment
		(start 59.672982 -281.919172)
		(end 58.656982 -282.935172)
		(width 0.18288)
		(layer "In2.Cu")
		(net "M_B_CPU1_SA_DQ<22>")
	)
	(segment
		(start 79.713074 -267.66393)
		(end 77.965554 -268.388084)
		(width 0.18288)
		(layer "In2.Cu")
		(net "M_B_CPU1_SA_DQ<22>")
	)
	(segment
		(start 83.626198 -264.100564)
		(end 83.539838 -264.136378)
		(width 0.088646)
		(layer "In2.Cu")
		(net "M_B_CPU1_SA_DQ<22>")
	)
	(segment
		(start 66.300858 -281.140154)
		(end 65.939416 -281.140154)
		(width 0.18288)
		(layer "In2.Cu")
		(net "M_B_CPU1_SA_DQ<22>")
	)
	(segment
		(start 77.474572 -268.87932)
		(end 68.54825 -277.80869)
		(width 0.18288)
		(layer "In2.Cu")
		(net "M_B_CPU1_SA_DQ<22>")
	)
	(segment
		(start 65.939416 -281.140154)
		(end 65.482724 -280.683462)
		(width 0.18288)
		(layer "In2.Cu")
		(net "M_B_CPU1_SA_DQ<22>")
	)
	(segment
		(start 55.255668 -284.514798)
		(end 55.431182 -284.690312)
		(width 0.18288)
		(layer "In2.Cu")
		(net "M_B_CPU1_SA_DQ<22>")
	)
	(segment
		(start 60.34151 -281.919172)
		(end 59.672982 -281.919172)
		(width 0.18288)
		(layer "In2.Cu")
		(net "M_B_CPU1_SA_DQ<22>")
	)
	(segment
		(start 62.964568 -281.298142)
		(end 62.343538 -281.919172)
		(width 0.18288)
		(layer "In2.Cu")
		(net "M_B_CPU1_SA_DQ<22>")
	)
	(segment
		(start 58.250582 -283.620972)
		(end 56.65089 -283.620972)
		(width 0.18288)
		(layer "In2.Cu")
		(net "M_B_CPU1_SA_DQ<22>")
	)
	(arc
		(start 85.248496 -264.010902)
		(mid 84.965794 -263.935126)
		(end 84.683092 -264.010902)
		(width 0.088646)
		(layer "In2.Cu")
		(net "M_B_CPU1_SA_DQ<22>")
	)
	(arc
		(start 83.743292 -264.010902)
		(mid 83.681814 -264.051904)
		(end 83.626198 -264.100564)
		(width 0.088646)
		(layer "In2.Cu")
		(net "M_B_CPU1_SA_DQ<22>")
	)
	(arc
		(start 89.382092 -264.010902)
		(mid 89.194894 -264.061045)
		(end 89.007696 -264.010902)
		(width 0.088646)
		(layer "In2.Cu")
		(net "M_B_CPU1_SA_DQ<22>")
	)
	(arc
		(start 84.308696 -264.010902)
		(mid 84.025994 -263.935126)
		(end 83.743292 -264.010902)
		(width 0.088646)
		(layer "In2.Cu")
		(net "M_B_CPU1_SA_DQ<22>")
	)
	(arc
		(start 89.947496 -264.010902)
		(mid 89.664794 -263.935126)
		(end 89.382092 -264.010902)
		(width 0.088646)
		(layer "In2.Cu")
		(net "M_B_CPU1_SA_DQ<22>")
	)
	(arc
		(start 87.502492 -264.010902)
		(mid 87.315294 -264.061045)
		(end 87.128096 -264.010902)
		(width 0.088646)
		(layer "In2.Cu")
		(net "M_B_CPU1_SA_DQ<22>")
	)
	(arc
		(start 89.007696 -264.010902)
		(mid 88.724994 -263.935126)
		(end 88.442292 -264.010902)
		(width 0.088646)
		(layer "In2.Cu")
		(net "M_B_CPU1_SA_DQ<22>")
	)
	(arc
		(start 90.226388 -264.434828)
		(mid 90.137214 -264.189786)
		(end 89.947496 -264.010902)
		(width 0.088646)
		(layer "In2.Cu")
		(net "M_B_CPU1_SA_DQ<22>")
	)
	(arc
		(start 87.128096 -264.010902)
		(mid 86.845394 -263.935126)
		(end 86.562692 -264.010902)
		(width 0.088646)
		(layer "In2.Cu")
		(net "M_B_CPU1_SA_DQ<22>")
	)
	(arc
		(start 88.067896 -264.010902)
		(mid 87.785194 -263.935126)
		(end 87.502492 -264.010902)
		(width 0.088646)
		(layer "In2.Cu")
		(net "M_B_CPU1_SA_DQ<22>")
	)
	(arc
		(start 86.562692 -264.010902)
		(mid 86.375494 -264.061045)
		(end 86.188296 -264.010902)
		(width 0.088646)
		(layer "In2.Cu")
		(net "M_B_CPU1_SA_DQ<22>")
	)
	(arc
		(start 88.442292 -264.010902)
		(mid 88.255094 -264.061045)
		(end 88.067896 -264.010902)
		(width 0.088646)
		(layer "In2.Cu")
		(net "M_B_CPU1_SA_DQ<22>")
	)
	(arc
		(start 84.683092 -264.010902)
		(mid 84.495894 -264.061045)
		(end 84.308696 -264.010902)
		(width 0.088646)
		(layer "In2.Cu")
		(net "M_B_CPU1_SA_DQ<22>")
	)
	(arc
		(start 85.622892 -264.010902)
		(mid 85.435694 -264.061045)
		(end 85.248496 -264.010902)
		(width 0.088646)
		(layer "In2.Cu")
		(net "M_B_CPU1_SA_DQ<22>")
	)
	(arc
		(start 86.188296 -264.010902)
		(mid 85.905594 -263.935126)
		(end 85.622892 -264.010902)
		(width 0.088646)
		(layer "In2.Cu")
		(net "M_B_CPU1_SA_DQ<22>")
	)
	(segment
		(start 40.682672 -289.532822)
		(end 40.520112 -289.695382)
		(width 0.20066)
		(layer "F.Cu")
		(net "M_B_CPU1_SA_DQ<21>")
	)
	(segment
		(start 89.194894 -263.150604)
		(end 89.194894 -263.686544)
		(width 0.20066)
		(layer "F.Cu")
		(net "M_B_CPU1_SA_DQ<21>")
	)
	(segment
		(start 43.616626 -289.541712)
		(end 43.285918 -289.541712)
		(width 0.101854)
		(layer "F.Cu")
		(net "M_B_CPU1_SA_DQ<21>")
	)
	(segment
		(start 40.520112 -289.695382)
		(end 40.520112 -290.02355)
		(width 0.20066)
		(layer "F.Cu")
		(net "M_B_CPU1_SA_DQ<21>")
	)
	(segment
		(start 39.861236 -290.177982)
		(end 39.649908 -289.966654)
		(width 0.20066)
		(layer "F.Cu")
		(net "M_B_CPU1_SA_DQ<21>")
	)
	(segment
		(start 43.285918 -289.541712)
		(end 41.3004 -289.541712)
		(width 0.1016)
		(layer "F.Cu")
		(net "M_B_CPU1_SA_DQ<21>")
	)
	(segment
		(start 46.964346 -289.966654)
		(end 45.859446 -289.966654)
		(width 0.20066)
		(layer "F.Cu")
		(net "M_B_CPU1_SA_DQ<21>")
	)
	(segment
		(start 39.649908 -289.966654)
		(end 38.315646 -289.966654)
		(width 0.20066)
		(layer "F.Cu")
		(net "M_B_CPU1_SA_DQ<21>")
	)
	(segment
		(start 43.795188 -289.541712)
		(end 43.616626 -289.541712)
		(width 0.20066)
		(layer "F.Cu")
		(net "M_B_CPU1_SA_DQ<21>")
	)
	(segment
		(start 45.859446 -289.966654)
		(end 44.22013 -289.966654)
		(width 0.20066)
		(layer "F.Cu")
		(net "M_B_CPU1_SA_DQ<21>")
	)
	(segment
		(start 44.22013 -289.966654)
		(end 43.795188 -289.541712)
		(width 0.20066)
		(layer "F.Cu")
		(net "M_B_CPU1_SA_DQ<21>")
	)
	(segment
		(start 41.29151 -289.532822)
		(end 40.682672 -289.532822)
		(width 0.20066)
		(layer "F.Cu")
		(net "M_B_CPU1_SA_DQ<21>")
	)
	(segment
		(start 40.520112 -290.02355)
		(end 40.36568 -290.177982)
		(width 0.20066)
		(layer "F.Cu")
		(net "M_B_CPU1_SA_DQ<21>")
	)
	(segment
		(start 40.36568 -290.177982)
		(end 39.861236 -290.177982)
		(width 0.20066)
		(layer "F.Cu")
		(net "M_B_CPU1_SA_DQ<21>")
	)
	(segment
		(start 41.3004 -289.541712)
		(end 41.29151 -289.532822)
		(width 0.1016)
		(layer "F.Cu")
		(net "M_B_CPU1_SA_DQ<21>")
	)
	(segment
		(start 66.38798 -280.135584)
		(end 63.79337 -280.135584)
		(width 0.18288)
		(layer "In2.Cu")
		(net "M_B_CPU1_SA_DQ<21>")
	)
	(segment
		(start 47.705518 -289.225482)
		(end 46.964346 -289.966654)
		(width 0.18288)
		(layer "In2.Cu")
		(net "M_B_CPU1_SA_DQ<21>")
	)
	(segment
		(start 59.622182 -281.030172)
		(end 58.773822 -281.878532)
		(width 0.18288)
		(layer "In2.Cu")
		(net "M_B_CPU1_SA_DQ<21>")
	)
	(segment
		(start 52.840382 -285.500572)
		(end 52.840382 -285.957772)
		(width 0.18288)
		(layer "In2.Cu")
		(net "M_B_CPU1_SA_DQ<21>")
	)
	(segment
		(start 77.345286 -268.27099)
		(end 67.968876 -277.6474)
		(width 0.18288)
		(layer "In2.Cu")
		(net "M_B_CPU1_SA_DQ<21>")
	)
	(segment
		(start 63.370714 -280.55824)
		(end 62.23127 -281.030172)
		(width 0.18288)
		(layer "In2.Cu")
		(net "M_B_CPU1_SA_DQ<21>")
	)
	(segment
		(start 49.099978 -289.541712)
		(end 48.783748 -289.225482)
		(width 0.18288)
		(layer "In2.Cu")
		(net "M_B_CPU1_SA_DQ<21>")
	)
	(segment
		(start 52.433982 -285.094172)
		(end 52.840382 -285.500572)
		(width 0.18288)
		(layer "In2.Cu")
		(net "M_B_CPU1_SA_DQ<21>")
	)
	(segment
		(start 58.773822 -281.878532)
		(end 57.619138 -281.878532)
		(width 0.18288)
		(layer "In2.Cu")
		(net "M_B_CPU1_SA_DQ<21>")
	)
	(segment
		(start 89.390982 -263.367266)
		(end 89.382092 -263.362186)
		(width 0.088646)
		(layer "In2.Cu")
		(net "M_B_CPU1_SA_DQ<21>")
	)
	(segment
		(start 79.511906 -267.3731)
		(end 77.345286 -268.27099)
		(width 0.18288)
		(layer "In2.Cu")
		(net "M_B_CPU1_SA_DQ<21>")
	)
	(segment
		(start 51.722782 -287.075372)
		(end 51.722782 -289.236658)
		(width 0.18288)
		(layer "In2.Cu")
		(net "M_B_CPU1_SA_DQ<21>")
	)
	(segment
		(start 81.345024 -265.539982)
		(end 81.260188 -265.624818)
		(width 0.088646)
		(layer "In2.Cu")
		(net "M_B_CPU1_SA_DQ<21>")
	)
	(segment
		(start 62.23127 -281.030172)
		(end 59.622182 -281.030172)
		(width 0.18288)
		(layer "In2.Cu")
		(net "M_B_CPU1_SA_DQ<21>")
	)
	(segment
		(start 83.989672 -263.436862)
		(end 83.853274 -263.436862)
		(width 0.088646)
		(layer "In2.Cu")
		(net "M_B_CPU1_SA_DQ<21>")
	)
	(segment
		(start 89.194894 -263.686544)
		(end 89.507822 -263.686544)
		(width 0.088646)
		(layer "In2.Cu")
		(net "M_B_CPU1_SA_DQ<21>")
	)
	(segment
		(start 54.458362 -283.737558)
		(end 54.159658 -283.438854)
		(width 0.18288)
		(layer "In2.Cu")
		(net "M_B_CPU1_SA_DQ<21>")
	)
	(segment
		(start 56.303672 -283.193998)
		(end 55.40121 -283.193998)
		(width 0.18288)
		(layer "In2.Cu")
		(net "M_B_CPU1_SA_DQ<21>")
	)
	(segment
		(start 83.853274 -263.436862)
		(end 81.750154 -265.539982)
		(width 0.088646)
		(layer "In2.Cu")
		(net "M_B_CPU1_SA_DQ<21>")
	)
	(segment
		(start 51.722782 -289.236658)
		(end 51.417728 -289.541712)
		(width 0.18288)
		(layer "In2.Cu")
		(net "M_B_CPU1_SA_DQ<21>")
	)
	(segment
		(start 81.260188 -265.624818)
		(end 79.511906 -267.3731)
		(width 0.18288)
		(layer "In2.Cu")
		(net "M_B_CPU1_SA_DQ<21>")
	)
	(segment
		(start 81.750154 -265.539982)
		(end 81.345024 -265.539982)
		(width 0.088646)
		(layer "In2.Cu")
		(net "M_B_CPU1_SA_DQ<21>")
	)
	(segment
		(start 52.433982 -283.762958)
		(end 52.433982 -285.094172)
		(width 0.18288)
		(layer "In2.Cu")
		(net "M_B_CPU1_SA_DQ<21>")
	)
	(segment
		(start 67.968876 -277.6474)
		(end 67.968876 -278.554688)
		(width 0.18288)
		(layer "In2.Cu")
		(net "M_B_CPU1_SA_DQ<21>")
	)
	(segment
		(start 51.417728 -289.541712)
		(end 49.099978 -289.541712)
		(width 0.18288)
		(layer "In2.Cu")
		(net "M_B_CPU1_SA_DQ<21>")
	)
	(segment
		(start 63.79337 -280.135584)
		(end 63.370714 -280.55824)
		(width 0.18288)
		(layer "In2.Cu")
		(net "M_B_CPU1_SA_DQ<21>")
	)
	(segment
		(start 89.507822 -263.686544)
		(end 89.564972 -263.629394)
		(width 0.088646)
		(layer "In2.Cu")
		(net "M_B_CPU1_SA_DQ<21>")
	)
	(segment
		(start 54.85765 -283.737558)
		(end 54.458362 -283.737558)
		(width 0.18288)
		(layer "In2.Cu")
		(net "M_B_CPU1_SA_DQ<21>")
	)
	(segment
		(start 67.968876 -278.554688)
		(end 66.38798 -280.135584)
		(width 0.18288)
		(layer "In2.Cu")
		(net "M_B_CPU1_SA_DQ<21>")
	)
	(segment
		(start 52.840382 -285.957772)
		(end 51.722782 -287.075372)
		(width 0.18288)
		(layer "In2.Cu")
		(net "M_B_CPU1_SA_DQ<21>")
	)
	(segment
		(start 48.783748 -289.225482)
		(end 47.705518 -289.225482)
		(width 0.18288)
		(layer "In2.Cu")
		(net "M_B_CPU1_SA_DQ<21>")
	)
	(segment
		(start 57.619138 -281.878532)
		(end 56.303672 -283.193998)
		(width 0.18288)
		(layer "In2.Cu")
		(net "M_B_CPU1_SA_DQ<21>")
	)
	(segment
		(start 54.159658 -283.438854)
		(end 52.758086 -283.438854)
		(width 0.18288)
		(layer "In2.Cu")
		(net "M_B_CPU1_SA_DQ<21>")
	)
	(segment
		(start 52.758086 -283.438854)
		(end 52.433982 -283.762958)
		(width 0.18288)
		(layer "In2.Cu")
		(net "M_B_CPU1_SA_DQ<21>")
	)
	(segment
		(start 55.40121 -283.193998)
		(end 54.85765 -283.737558)
		(width 0.18288)
		(layer "In2.Cu")
		(net "M_B_CPU1_SA_DQ<21>")
	)
	(arc
		(start 86.188296 -263.362186)
		(mid 85.905594 -263.437928)
		(end 85.622892 -263.362186)
		(width 0.088646)
		(layer "In2.Cu")
		(net "M_B_CPU1_SA_DQ<21>")
	)
	(arc
		(start 89.564972 -263.629394)
		(mid 89.506853 -263.479153)
		(end 89.390982 -263.367266)
		(width 0.088646)
		(layer "In2.Cu")
		(net "M_B_CPU1_SA_DQ<21>")
	)
	(arc
		(start 85.248496 -263.362186)
		(mid 84.965794 -263.437962)
		(end 84.683092 -263.362186)
		(width 0.088646)
		(layer "In2.Cu")
		(net "M_B_CPU1_SA_DQ<21>")
	)
	(arc
		(start 86.562692 -263.362186)
		(mid 86.375494 -263.312043)
		(end 86.188296 -263.362186)
		(width 0.088646)
		(layer "In2.Cu")
		(net "M_B_CPU1_SA_DQ<21>")
	)
	(arc
		(start 87.128096 -263.362186)
		(mid 86.845394 -263.437928)
		(end 86.562692 -263.362186)
		(width 0.088646)
		(layer "In2.Cu")
		(net "M_B_CPU1_SA_DQ<21>")
	)
	(arc
		(start 84.683092 -263.362186)
		(mid 84.495894 -263.312043)
		(end 84.308696 -263.362186)
		(width 0.088646)
		(layer "In2.Cu")
		(net "M_B_CPU1_SA_DQ<21>")
	)
	(arc
		(start 88.442292 -263.362186)
		(mid 88.255094 -263.312043)
		(end 88.067896 -263.362186)
		(width 0.088646)
		(layer "In2.Cu")
		(net "M_B_CPU1_SA_DQ<21>")
	)
	(arc
		(start 84.308696 -263.362186)
		(mid 84.154712 -263.423154)
		(end 83.989672 -263.436862)
		(width 0.088646)
		(layer "In2.Cu")
		(net "M_B_CPU1_SA_DQ<21>")
	)
	(arc
		(start 89.007696 -263.362186)
		(mid 88.724994 -263.437928)
		(end 88.442292 -263.362186)
		(width 0.088646)
		(layer "In2.Cu")
		(net "M_B_CPU1_SA_DQ<21>")
	)
	(arc
		(start 88.067896 -263.362186)
		(mid 87.785194 -263.437928)
		(end 87.502492 -263.362186)
		(width 0.088646)
		(layer "In2.Cu")
		(net "M_B_CPU1_SA_DQ<21>")
	)
	(arc
		(start 87.502492 -263.362186)
		(mid 87.315294 -263.312043)
		(end 87.128096 -263.362186)
		(width 0.088646)
		(layer "In2.Cu")
		(net "M_B_CPU1_SA_DQ<21>")
	)
	(arc
		(start 85.622892 -263.362186)
		(mid 85.435694 -263.312043)
		(end 85.248496 -263.362186)
		(width 0.088646)
		(layer "In2.Cu")
		(net "M_B_CPU1_SA_DQ<21>")
	)
	(arc
		(start 89.382092 -263.362186)
		(mid 89.194894 -263.312043)
		(end 89.007696 -263.362186)
		(width 0.088646)
		(layer "In2.Cu")
		(net "M_B_CPU1_SA_DQ<21>")
	)
	(segment
		(start 40.729662 -291.233606)
		(end 40.520112 -291.443156)
		(width 0.20066)
		(layer "F.Cu")
		(net "M_B_CPU1_SA_DQ<20>")
	)
	(segment
		(start 44.065444 -291.241734)
		(end 43.616626 -291.241734)
		(width 0.20066)
		(layer "F.Cu")
		(net "M_B_CPU1_SA_DQ<20>")
	)
	(segment
		(start 41.547542 -291.241734)
		(end 41.299638 -291.241734)
		(width 0.101854)
		(layer "F.Cu")
		(net "M_B_CPU1_SA_DQ<20>")
	)
	(segment
		(start 39.888668 -291.905436)
		(end 39.649908 -291.666676)
		(width 0.20066)
		(layer "F.Cu")
		(net "M_B_CPU1_SA_DQ<20>")
	)
	(segment
		(start 41.299638 -291.241734)
		(end 41.29151 -291.233606)
		(width 0.101854)
		(layer "F.Cu")
		(net "M_B_CPU1_SA_DQ<20>")
	)
	(segment
		(start 39.649908 -291.666676)
		(end 38.315646 -291.666676)
		(width 0.20066)
		(layer "F.Cu")
		(net "M_B_CPU1_SA_DQ<20>")
	)
	(segment
		(start 45.859446 -291.666676)
		(end 44.490386 -291.666676)
		(width 0.20066)
		(layer "F.Cu")
		(net "M_B_CPU1_SA_DQ<20>")
	)
	(segment
		(start 88.725248 -264.500106)
		(end 88.724994 -264.50036)
		(width 0.20066)
		(layer "F.Cu")
		(net "M_B_CPU1_SA_DQ<20>")
	)
	(segment
		(start 44.490386 -291.666676)
		(end 44.065444 -291.241734)
		(width 0.20066)
		(layer "F.Cu")
		(net "M_B_CPU1_SA_DQ<20>")
	)
	(segment
		(start 40.520112 -291.443156)
		(end 40.520112 -291.732716)
		(width 0.20066)
		(layer "F.Cu")
		(net "M_B_CPU1_SA_DQ<20>")
	)
	(segment
		(start 88.725248 -263.96442)
		(end 88.725248 -264.500106)
		(width 0.20066)
		(layer "F.Cu")
		(net "M_B_CPU1_SA_DQ<20>")
	)
	(segment
		(start 43.616626 -291.241734)
		(end 41.547542 -291.241734)
		(width 0.1016)
		(layer "F.Cu")
		(net "M_B_CPU1_SA_DQ<20>")
	)
	(segment
		(start 46.964346 -291.666676)
		(end 45.859446 -291.666676)
		(width 0.20066)
		(layer "F.Cu")
		(net "M_B_CPU1_SA_DQ<20>")
	)
	(segment
		(start 40.520112 -291.732716)
		(end 40.347392 -291.905436)
		(width 0.20066)
		(layer "F.Cu")
		(net "M_B_CPU1_SA_DQ<20>")
	)
	(segment
		(start 41.29151 -291.233606)
		(end 40.729662 -291.233606)
		(width 0.20066)
		(layer "F.Cu")
		(net "M_B_CPU1_SA_DQ<20>")
	)
	(segment
		(start 40.347392 -291.905436)
		(end 39.888668 -291.905436)
		(width 0.20066)
		(layer "F.Cu")
		(net "M_B_CPU1_SA_DQ<20>")
	)
	(segment
		(start 49.077372 -291.196014)
		(end 47.435008 -291.196014)
		(width 0.18288)
		(layer "In2.Cu")
		(net "M_B_CPU1_SA_DQ<20>")
	)
	(segment
		(start 47.435008 -291.196014)
		(end 46.964346 -291.666676)
		(width 0.18288)
		(layer "In2.Cu")
		(net "M_B_CPU1_SA_DQ<20>")
	)
	(segment
		(start 59.394598 -283.891736)
		(end 59.394598 -284.117796)
		(width 0.18288)
		(layer "In2.Cu")
		(net "M_B_CPU1_SA_DQ<20>")
	)
	(segment
		(start 81.91119 -265.958574)
		(end 81.752694 -266.11707)
		(width 0.088646)
		(layer "In2.Cu")
		(net "M_B_CPU1_SA_DQ<20>")
	)
	(segment
		(start 81.752694 -266.11707)
		(end 79.915512 -267.954252)
		(width 0.18288)
		(layer "In2.Cu")
		(net "M_B_CPU1_SA_DQ<20>")
	)
	(segment
		(start 60.804298 -283.229558)
		(end 60.644278 -283.069538)
		(width 0.18288)
		(layer "In2.Cu")
		(net "M_B_CPU1_SA_DQ<20>")
	)
	(segment
		(start 60.644278 -283.069538)
		(end 60.644278 -282.881578)
		(width 0.18288)
		(layer "In2.Cu")
		(net "M_B_CPU1_SA_DQ<20>")
	)
	(segment
		(start 88.921082 -264.181082)
		(end 88.912192 -264.176002)
		(width 0.088646)
		(layer "In2.Cu")
		(net "M_B_CPU1_SA_DQ<20>")
	)
	(segment
		(start 82.019394 -265.958574)
		(end 81.91119 -265.958574)
		(width 0.088646)
		(layer "In2.Cu")
		(net "M_B_CPU1_SA_DQ<20>")
	)
	(segment
		(start 55.031894 -286.47898)
		(end 55.031894 -289.491166)
		(width 0.18288)
		(layer "In2.Cu")
		(net "M_B_CPU1_SA_DQ<20>")
	)
	(segment
		(start 69.067934 -278.012906)
		(end 69.067934 -279.091644)
		(width 0.18288)
		(layer "In2.Cu")
		(net "M_B_CPU1_SA_DQ<20>")
	)
	(segment
		(start 89.037668 -264.50036)
		(end 89.095072 -264.442956)
		(width 0.088646)
		(layer "In2.Cu")
		(net "M_B_CPU1_SA_DQ<20>")
	)
	(segment
		(start 61.472572 -283.069538)
		(end 61.312552 -283.229558)
		(width 0.18288)
		(layer "In2.Cu")
		(net "M_B_CPU1_SA_DQ<20>")
	)
	(segment
		(start 83.760818 -264.235184)
		(end 83.515454 -264.480548)
		(width 0.088646)
		(layer "In2.Cu")
		(net "M_B_CPU1_SA_DQ<20>")
	)
	(segment
		(start 83.48472 -264.493248)
		(end 82.019394 -265.958574)
		(width 0.088646)
		(layer "In2.Cu")
		(net "M_B_CPU1_SA_DQ<20>")
	)
	(segment
		(start 59.092592 -284.419802)
		(end 58.856626 -284.419802)
		(width 0.18288)
		(layer "In2.Cu")
		(net "M_B_CPU1_SA_DQ<20>")
	)
	(segment
		(start 58.856626 -284.419802)
		(end 58.686446 -284.249622)
		(width 0.18288)
		(layer "In2.Cu")
		(net "M_B_CPU1_SA_DQ<20>")
	)
	(segment
		(start 59.244484 -283.138626)
		(end 59.244484 -283.741622)
		(width 0.18288)
		(layer "In2.Cu")
		(net "M_B_CPU1_SA_DQ<20>")
	)
	(segment
		(start 50.82413 -291.241734)
		(end 50.592736 -291.473128)
		(width 0.18288)
		(layer "In2.Cu")
		(net "M_B_CPU1_SA_DQ<20>")
	)
	(segment
		(start 83.515454 -264.480548)
		(end 83.48472 -264.493248)
		(width 0.088646)
		(layer "In2.Cu")
		(net "M_B_CPU1_SA_DQ<20>")
	)
	(segment
		(start 57.375298 -285.334456)
		(end 56.176418 -285.334456)
		(width 0.18288)
		(layer "In2.Cu")
		(net "M_B_CPU1_SA_DQ<20>")
	)
	(segment
		(start 55.031894 -289.491166)
		(end 53.236876 -291.286184)
		(width 0.18288)
		(layer "In2.Cu")
		(net "M_B_CPU1_SA_DQ<20>")
	)
	(segment
		(start 61.632592 -282.721558)
		(end 61.472572 -282.881578)
		(width 0.18288)
		(layer "In2.Cu")
		(net "M_B_CPU1_SA_DQ<20>")
	)
	(segment
		(start 62.566296 -282.721558)
		(end 61.632592 -282.721558)
		(width 0.18288)
		(layer "In2.Cu")
		(net "M_B_CPU1_SA_DQ<20>")
	)
	(segment
		(start 60.644278 -282.881578)
		(end 60.484258 -282.721558)
		(width 0.18288)
		(layer "In2.Cu")
		(net "M_B_CPU1_SA_DQ<20>")
	)
	(segment
		(start 53.236876 -291.286184)
		(end 51.406044 -291.286184)
		(width 0.18288)
		(layer "In2.Cu")
		(net "M_B_CPU1_SA_DQ<20>")
	)
	(segment
		(start 60.484258 -282.721558)
		(end 59.661552 -282.721558)
		(width 0.18288)
		(layer "In2.Cu")
		(net "M_B_CPU1_SA_DQ<20>")
	)
	(segment
		(start 79.915512 -267.954252)
		(end 78.56855 -268.51229)
		(width 0.18288)
		(layer "In2.Cu")
		(net "M_B_CPU1_SA_DQ<20>")
	)
	(segment
		(start 88.724994 -264.50036)
		(end 89.037668 -264.50036)
		(width 0.088646)
		(layer "In2.Cu")
		(net "M_B_CPU1_SA_DQ<20>")
	)
	(segment
		(start 66.314828 -281.84475)
		(end 63.443104 -281.84475)
		(width 0.18288)
		(layer "In2.Cu")
		(net "M_B_CPU1_SA_DQ<20>")
	)
	(segment
		(start 50.592736 -291.473128)
		(end 49.354486 -291.473128)
		(width 0.18288)
		(layer "In2.Cu")
		(net "M_B_CPU1_SA_DQ<20>")
	)
	(segment
		(start 49.354486 -291.473128)
		(end 49.077372 -291.196014)
		(width 0.18288)
		(layer "In2.Cu")
		(net "M_B_CPU1_SA_DQ<20>")
	)
	(segment
		(start 59.661552 -282.721558)
		(end 59.244484 -283.138626)
		(width 0.18288)
		(layer "In2.Cu")
		(net "M_B_CPU1_SA_DQ<20>")
	)
	(segment
		(start 59.244484 -283.741622)
		(end 59.394598 -283.891736)
		(width 0.18288)
		(layer "In2.Cu")
		(net "M_B_CPU1_SA_DQ<20>")
	)
	(segment
		(start 51.406044 -291.286184)
		(end 51.361594 -291.241734)
		(width 0.18288)
		(layer "In2.Cu")
		(net "M_B_CPU1_SA_DQ<20>")
	)
	(segment
		(start 61.472572 -282.881578)
		(end 61.472572 -283.069538)
		(width 0.18288)
		(layer "In2.Cu")
		(net "M_B_CPU1_SA_DQ<20>")
	)
	(segment
		(start 58.686446 -284.249622)
		(end 58.460132 -284.249622)
		(width 0.18288)
		(layer "In2.Cu")
		(net "M_B_CPU1_SA_DQ<20>")
	)
	(segment
		(start 58.460132 -284.249622)
		(end 57.375298 -285.334456)
		(width 0.18288)
		(layer "In2.Cu")
		(net "M_B_CPU1_SA_DQ<20>")
	)
	(segment
		(start 78.56855 -268.51229)
		(end 69.067934 -278.012906)
		(width 0.18288)
		(layer "In2.Cu")
		(net "M_B_CPU1_SA_DQ<20>")
	)
	(segment
		(start 59.394598 -284.117796)
		(end 59.092592 -284.419802)
		(width 0.18288)
		(layer "In2.Cu")
		(net "M_B_CPU1_SA_DQ<20>")
	)
	(segment
		(start 56.176418 -285.334456)
		(end 55.031894 -286.47898)
		(width 0.18288)
		(layer "In2.Cu")
		(net "M_B_CPU1_SA_DQ<20>")
	)
	(segment
		(start 69.067934 -279.091644)
		(end 66.314828 -281.84475)
		(width 0.18288)
		(layer "In2.Cu")
		(net "M_B_CPU1_SA_DQ<20>")
	)
	(segment
		(start 63.443104 -281.84475)
		(end 62.566296 -282.721558)
		(width 0.18288)
		(layer "In2.Cu")
		(net "M_B_CPU1_SA_DQ<20>")
	)
	(segment
		(start 51.361594 -291.241734)
		(end 50.82413 -291.241734)
		(width 0.18288)
		(layer "In2.Cu")
		(net "M_B_CPU1_SA_DQ<20>")
	)
	(segment
		(start 61.312552 -283.229558)
		(end 60.804298 -283.229558)
		(width 0.18288)
		(layer "In2.Cu")
		(net "M_B_CPU1_SA_DQ<20>")
	)
	(arc
		(start 83.838796 -264.176002)
		(mid 83.797866 -264.203035)
		(end 83.760818 -264.235184)
		(width 0.088646)
		(layer "In2.Cu")
		(net "M_B_CPU1_SA_DQ<20>")
	)
	(arc
		(start 85.718396 -264.176002)
		(mid 85.435694 -264.251778)
		(end 85.152992 -264.176002)
		(width 0.088646)
		(layer "In2.Cu")
		(net "M_B_CPU1_SA_DQ<20>")
	)
	(arc
		(start 89.095072 -264.442956)
		(mid 89.036916 -264.292843)
		(end 88.921082 -264.181082)
		(width 0.088646)
		(layer "In2.Cu")
		(net "M_B_CPU1_SA_DQ<20>")
	)
	(arc
		(start 87.032592 -264.176002)
		(mid 86.845394 -264.125859)
		(end 86.658196 -264.176002)
		(width 0.088646)
		(layer "In2.Cu")
		(net "M_B_CPU1_SA_DQ<20>")
	)
	(arc
		(start 84.213192 -264.176002)
		(mid 84.025994 -264.125859)
		(end 83.838796 -264.176002)
		(width 0.088646)
		(layer "In2.Cu")
		(net "M_B_CPU1_SA_DQ<20>")
	)
	(arc
		(start 88.537796 -264.176002)
		(mid 88.255094 -264.251778)
		(end 87.972392 -264.176002)
		(width 0.088646)
		(layer "In2.Cu")
		(net "M_B_CPU1_SA_DQ<20>")
	)
	(arc
		(start 84.778596 -264.176002)
		(mid 84.495894 -264.251778)
		(end 84.213192 -264.176002)
		(width 0.088646)
		(layer "In2.Cu")
		(net "M_B_CPU1_SA_DQ<20>")
	)
	(arc
		(start 85.152992 -264.176002)
		(mid 84.965794 -264.125859)
		(end 84.778596 -264.176002)
		(width 0.088646)
		(layer "In2.Cu")
		(net "M_B_CPU1_SA_DQ<20>")
	)
	(arc
		(start 87.972392 -264.176002)
		(mid 87.785194 -264.125859)
		(end 87.597996 -264.176002)
		(width 0.088646)
		(layer "In2.Cu")
		(net "M_B_CPU1_SA_DQ<20>")
	)
	(arc
		(start 88.912192 -264.176002)
		(mid 88.724994 -264.125859)
		(end 88.537796 -264.176002)
		(width 0.088646)
		(layer "In2.Cu")
		(net "M_B_CPU1_SA_DQ<20>")
	)
	(arc
		(start 86.658196 -264.176002)
		(mid 86.375494 -264.251778)
		(end 86.092792 -264.176002)
		(width 0.088646)
		(layer "In2.Cu")
		(net "M_B_CPU1_SA_DQ<20>")
	)
	(arc
		(start 87.597996 -264.176002)
		(mid 87.315294 -264.251778)
		(end 87.032592 -264.176002)
		(width 0.088646)
		(layer "In2.Cu")
		(net "M_B_CPU1_SA_DQ<20>")
	)
	(arc
		(start 86.092792 -264.176002)
		(mid 85.905594 -264.125859)
		(end 85.718396 -264.176002)
		(width 0.088646)
		(layer "In2.Cu")
		(net "M_B_CPU1_SA_DQ<20>")
	)
	(segment
		(start 43.285918 -314.19165)
		(end 41.3004 -314.19165)
		(width 0.1016)
		(layer "F.Cu")
		(net "M_B_CPU1_SA_DQ<1>")
	)
	(segment
		(start 40.682672 -314.18276)
		(end 40.520112 -314.34532)
		(width 0.20066)
		(layer "F.Cu")
		(net "M_B_CPU1_SA_DQ<1>")
	)
	(segment
		(start 43.616626 -314.19165)
		(end 43.285918 -314.19165)
		(width 0.101854)
		(layer "F.Cu")
		(net "M_B_CPU1_SA_DQ<1>")
	)
	(segment
		(start 45.859446 -314.616592)
		(end 44.22013 -314.616592)
		(width 0.20066)
		(layer "F.Cu")
		(net "M_B_CPU1_SA_DQ<1>")
	)
	(segment
		(start 41.29151 -314.18276)
		(end 40.682672 -314.18276)
		(width 0.20066)
		(layer "F.Cu")
		(net "M_B_CPU1_SA_DQ<1>")
	)
	(segment
		(start 39.861236 -314.82792)
		(end 39.649908 -314.616592)
		(width 0.20066)
		(layer "F.Cu")
		(net "M_B_CPU1_SA_DQ<1>")
	)
	(segment
		(start 40.520112 -314.673488)
		(end 40.36568 -314.82792)
		(width 0.20066)
		(layer "F.Cu")
		(net "M_B_CPU1_SA_DQ<1>")
	)
	(segment
		(start 43.795188 -314.19165)
		(end 43.616626 -314.19165)
		(width 0.20066)
		(layer "F.Cu")
		(net "M_B_CPU1_SA_DQ<1>")
	)
	(segment
		(start 88.725248 -275.35886)
		(end 88.725248 -275.894292)
		(width 0.20066)
		(layer "F.Cu")
		(net "M_B_CPU1_SA_DQ<1>")
	)
	(segment
		(start 41.3004 -314.19165)
		(end 41.29151 -314.18276)
		(width 0.1016)
		(layer "F.Cu")
		(net "M_B_CPU1_SA_DQ<1>")
	)
	(segment
		(start 46.964346 -314.616592)
		(end 45.859446 -314.616592)
		(width 0.20066)
		(layer "F.Cu")
		(net "M_B_CPU1_SA_DQ<1>")
	)
	(segment
		(start 44.22013 -314.616592)
		(end 43.795188 -314.19165)
		(width 0.20066)
		(layer "F.Cu")
		(net "M_B_CPU1_SA_DQ<1>")
	)
	(segment
		(start 40.520112 -314.34532)
		(end 40.520112 -314.673488)
		(width 0.20066)
		(layer "F.Cu")
		(net "M_B_CPU1_SA_DQ<1>")
	)
	(segment
		(start 40.36568 -314.82792)
		(end 39.861236 -314.82792)
		(width 0.20066)
		(layer "F.Cu")
		(net "M_B_CPU1_SA_DQ<1>")
	)
	(segment
		(start 39.649908 -314.616592)
		(end 38.315646 -314.616592)
		(width 0.20066)
		(layer "F.Cu")
		(net "M_B_CPU1_SA_DQ<1>")
	)
	(arc
		(start 88.725248 -275.894292)
		(mid 88.72519 -275.894584)
		(end 88.724994 -275.8948)
		(width 0.20066)
		(layer "F.Cu")
		(net "M_B_CPU1_SA_DQ<1>")
	)
	(segment
		(start 89.007188 -278.012398)
		(end 88.998298 -278.017478)
		(width 0.088646)
		(layer "In2.Cu")
		(net "M_B_CPU1_SA_DQ<1>")
	)
	(segment
		(start 47.689008 -314.173616)
		(end 47.407322 -314.173616)
		(width 0.18288)
		(layer "In2.Cu")
		(net "M_B_CPU1_SA_DQ<1>")
	)
	(segment
		(start 60.157868 -315.902086)
		(end 59.853068 -316.206886)
		(width 0.18288)
		(layer "In2.Cu")
		(net "M_B_CPU1_SA_DQ<1>")
	)
	(segment
		(start 83.54314 -286.617918)
		(end 81.032604 -289.128454)
		(width 0.18288)
		(layer "In2.Cu")
		(net "M_B_CPU1_SA_DQ<1>")
	)
	(segment
		(start 88.819736 -278.336756)
		(end 88.819736 -278.346662)
		(width 0.088646)
		(layer "In2.Cu")
		(net "M_B_CPU1_SA_DQ<1>")
	)
	(segment
		(start 84.220558 -282.407106)
		(end 84.220558 -284.982666)
		(width 0.18288)
		(layer "In2.Cu")
		(net "M_B_CPU1_SA_DQ<1>")
	)
	(segment
		(start 85.349842 -281.48788)
		(end 85.139784 -281.48788)
		(width 0.18288)
		(layer "In2.Cu")
		(net "M_B_CPU1_SA_DQ<1>")
	)
	(segment
		(start 84.0994 -285.275274)
		(end 83.54314 -286.617918)
		(width 0.18288)
		(layer "In2.Cu")
		(net "M_B_CPU1_SA_DQ<1>")
	)
	(segment
		(start 85.905594 -281.343354)
		(end 85.71738 -281.343354)
		(width 0.088646)
		(layer "In2.Cu")
		(net "M_B_CPU1_SA_DQ<1>")
	)
	(segment
		(start 81.032604 -289.128454)
		(end 76.427838 -300.245018)
		(width 0.18288)
		(layer "In2.Cu")
		(net "M_B_CPU1_SA_DQ<1>")
	)
	(segment
		(start 54.495954 -316.224158)
		(end 54.069996 -315.7982)
		(width 0.18288)
		(layer "In2.Cu")
		(net "M_B_CPU1_SA_DQ<1>")
	)
	(segment
		(start 48.584866 -314.173616)
		(end 48.284384 -314.474098)
		(width 0.18288)
		(layer "In2.Cu")
		(net "M_B_CPU1_SA_DQ<1>")
	)
	(segment
		(start 63.820802 -315.052964)
		(end 62.97168 -315.902086)
		(width 0.18288)
		(layer "In2.Cu")
		(net "M_B_CPU1_SA_DQ<1>")
	)
	(segment
		(start 53.442108 -315.171328)
		(end 53.260498 -314.989718)
		(width 0.18288)
		(layer "In2.Cu")
		(net "M_B_CPU1_SA_DQ<1>")
	)
	(segment
		(start 74.491088 -306.568094)
		(end 66.625978 -314.433204)
		(width 0.18288)
		(layer "In2.Cu")
		(net "M_B_CPU1_SA_DQ<1>")
	)
	(segment
		(start 49.10201 -314.173616)
		(end 48.584866 -314.173616)
		(width 0.18288)
		(layer "In2.Cu")
		(net "M_B_CPU1_SA_DQ<1>")
	)
	(segment
		(start 88.537796 -278.82596)
		(end 88.528906 -278.83104)
		(width 0.088646)
		(layer "In2.Cu")
		(net "M_B_CPU1_SA_DQ<1>")
	)
	(segment
		(start 56.50357 -315.771276)
		(end 55.556912 -315.771276)
		(width 0.18288)
		(layer "In2.Cu")
		(net "M_B_CPU1_SA_DQ<1>")
	)
	(segment
		(start 59.853068 -316.206886)
		(end 59.338464 -316.206886)
		(width 0.18288)
		(layer "In2.Cu")
		(net "M_B_CPU1_SA_DQ<1>")
	)
	(segment
		(start 53.442108 -315.60516)
		(end 53.442108 -315.171328)
		(width 0.18288)
		(layer "In2.Cu")
		(net "M_B_CPU1_SA_DQ<1>")
	)
	(segment
		(start 55.394098 -315.93409)
		(end 55.394098 -316.10808)
		(width 0.18288)
		(layer "In2.Cu")
		(net "M_B_CPU1_SA_DQ<1>")
	)
	(segment
		(start 85.572854 -281.48788)
		(end 85.349842 -281.48788)
		(width 0.088646)
		(layer "In2.Cu")
		(net "M_B_CPU1_SA_DQ<1>")
	)
	(segment
		(start 88.998806 -277.027894)
		(end 89.007696 -277.032974)
		(width 0.088646)
		(layer "In2.Cu")
		(net "M_B_CPU1_SA_DQ<1>")
	)
	(segment
		(start 58.370978 -315.861446)
		(end 58.216038 -316.016386)
		(width 0.18288)
		(layer "In2.Cu")
		(net "M_B_CPU1_SA_DQ<1>")
	)
	(segment
		(start 62.97168 -315.902086)
		(end 60.157868 -315.902086)
		(width 0.18288)
		(layer "In2.Cu")
		(net "M_B_CPU1_SA_DQ<1>")
	)
	(segment
		(start 88.067896 -279.639776)
		(end 88.059006 -279.644856)
		(width 0.088646)
		(layer "In2.Cu")
		(net "M_B_CPU1_SA_DQ<1>")
	)
	(segment
		(start 86.470744 -280.778204)
		(end 86.470744 -280.78811)
		(width 0.088646)
		(layer "In2.Cu")
		(net "M_B_CPU1_SA_DQ<1>")
	)
	(segment
		(start 50.221642 -314.19419)
		(end 49.862232 -314.5536)
		(width 0.18288)
		(layer "In2.Cu")
		(net "M_B_CPU1_SA_DQ<1>")
	)
	(segment
		(start 53.635148 -315.7982)
		(end 53.442108 -315.60516)
		(width 0.18288)
		(layer "In2.Cu")
		(net "M_B_CPU1_SA_DQ<1>")
	)
	(segment
		(start 89.015316 -278.007572)
		(end 89.007188 -278.012398)
		(width 0.088646)
		(layer "In2.Cu")
		(net "M_B_CPU1_SA_DQ<1>")
	)
	(segment
		(start 88.822276 -276.39518)
		(end 88.820244 -276.708616)
		(width 0.088646)
		(layer "In2.Cu")
		(net "M_B_CPU1_SA_DQ<1>")
	)
	(segment
		(start 52.042314 -314.989718)
		(end 51.246786 -314.19419)
		(width 0.18288)
		(layer "In2.Cu")
		(net "M_B_CPU1_SA_DQ<1>")
	)
	(segment
		(start 87.880444 -279.964134)
		(end 87.880444 -279.982676)
		(width 0.088646)
		(layer "In2.Cu")
		(net "M_B_CPU1_SA_DQ<1>")
	)
	(segment
		(start 47.407322 -314.173616)
		(end 46.964346 -314.616592)
		(width 0.18288)
		(layer "In2.Cu")
		(net "M_B_CPU1_SA_DQ<1>")
	)
	(segment
		(start 54.069996 -315.7982)
		(end 53.635148 -315.7982)
		(width 0.18288)
		(layer "In2.Cu")
		(net "M_B_CPU1_SA_DQ<1>")
	)
	(segment
		(start 86.658196 -280.453846)
		(end 86.649306 -280.458926)
		(width 0.088646)
		(layer "In2.Cu")
		(net "M_B_CPU1_SA_DQ<1>")
	)
	(segment
		(start 51.246786 -314.19419)
		(end 50.221642 -314.19419)
		(width 0.18288)
		(layer "In2.Cu")
		(net "M_B_CPU1_SA_DQ<1>")
	)
	(segment
		(start 88.724994 -275.8948)
		(end 88.822276 -276.39518)
		(width 0.088646)
		(layer "In2.Cu")
		(net "M_B_CPU1_SA_DQ<1>")
	)
	(segment
		(start 58.216038 -316.016386)
		(end 56.74868 -316.016386)
		(width 0.18288)
		(layer "In2.Cu")
		(net "M_B_CPU1_SA_DQ<1>")
	)
	(segment
		(start 49.481994 -314.5536)
		(end 49.10201 -314.173616)
		(width 0.18288)
		(layer "In2.Cu")
		(net "M_B_CPU1_SA_DQ<1>")
	)
	(segment
		(start 58.993024 -315.861446)
		(end 58.370978 -315.861446)
		(width 0.18288)
		(layer "In2.Cu")
		(net "M_B_CPU1_SA_DQ<1>")
	)
	(segment
		(start 48.284384 -314.474098)
		(end 47.98949 -314.474098)
		(width 0.18288)
		(layer "In2.Cu")
		(net "M_B_CPU1_SA_DQ<1>")
	)
	(segment
		(start 75.796902 -303.415446)
		(end 74.491088 -306.568094)
		(width 0.18288)
		(layer "In2.Cu")
		(net "M_B_CPU1_SA_DQ<1>")
	)
	(segment
		(start 66.625978 -314.746132)
		(end 66.319146 -315.052964)
		(width 0.18288)
		(layer "In2.Cu")
		(net "M_B_CPU1_SA_DQ<1>")
	)
	(segment
		(start 84.220558 -284.982666)
		(end 84.0994 -285.275274)
		(width 0.18288)
		(layer "In2.Cu")
		(net "M_B_CPU1_SA_DQ<1>")
	)
	(segment
		(start 47.98949 -314.474098)
		(end 47.689008 -314.173616)
		(width 0.18288)
		(layer "In2.Cu")
		(net "M_B_CPU1_SA_DQ<1>")
	)
	(segment
		(start 66.625978 -314.433204)
		(end 66.625978 -314.746132)
		(width 0.18288)
		(layer "In2.Cu")
		(net "M_B_CPU1_SA_DQ<1>")
	)
	(segment
		(start 55.27802 -316.224158)
		(end 54.495954 -316.224158)
		(width 0.18288)
		(layer "In2.Cu")
		(net "M_B_CPU1_SA_DQ<1>")
	)
	(segment
		(start 89.28989 -277.508208)
		(end 89.290144 -277.522432)
		(width 0.088646)
		(layer "In2.Cu")
		(net "M_B_CPU1_SA_DQ<1>")
	)
	(segment
		(start 66.319146 -315.052964)
		(end 63.820802 -315.052964)
		(width 0.18288)
		(layer "In2.Cu")
		(net "M_B_CPU1_SA_DQ<1>")
	)
	(segment
		(start 88.537542 -278.826214)
		(end 88.537796 -278.82596)
		(width 0.088646)
		(layer "In2.Cu")
		(net "M_B_CPU1_SA_DQ<1>")
	)
	(segment
		(start 55.556912 -315.771276)
		(end 55.394098 -315.93409)
		(width 0.18288)
		(layer "In2.Cu")
		(net "M_B_CPU1_SA_DQ<1>")
	)
	(segment
		(start 49.862232 -314.5536)
		(end 49.481994 -314.5536)
		(width 0.18288)
		(layer "In2.Cu")
		(net "M_B_CPU1_SA_DQ<1>")
	)
	(segment
		(start 59.338464 -316.206886)
		(end 58.993024 -315.861446)
		(width 0.18288)
		(layer "In2.Cu")
		(net "M_B_CPU1_SA_DQ<1>")
	)
	(segment
		(start 85.139784 -281.48788)
		(end 84.220558 -282.407106)
		(width 0.18288)
		(layer "In2.Cu")
		(net "M_B_CPU1_SA_DQ<1>")
	)
	(segment
		(start 55.394098 -316.10808)
		(end 55.27802 -316.224158)
		(width 0.18288)
		(layer "In2.Cu")
		(net "M_B_CPU1_SA_DQ<1>")
	)
	(segment
		(start 88.350344 -279.150318)
		(end 88.350344 -279.160224)
		(width 0.088646)
		(layer "In2.Cu")
		(net "M_B_CPU1_SA_DQ<1>")
	)
	(segment
		(start 53.260498 -314.989718)
		(end 52.042314 -314.989718)
		(width 0.18288)
		(layer "In2.Cu")
		(net "M_B_CPU1_SA_DQ<1>")
	)
	(segment
		(start 76.427838 -300.245018)
		(end 75.796902 -303.415446)
		(width 0.18288)
		(layer "In2.Cu")
		(net "M_B_CPU1_SA_DQ<1>")
	)
	(segment
		(start 85.71738 -281.343354)
		(end 85.572854 -281.48788)
		(width 0.088646)
		(layer "In2.Cu")
		(net "M_B_CPU1_SA_DQ<1>")
	)
	(segment
		(start 56.74868 -316.016386)
		(end 56.50357 -315.771276)
		(width 0.18288)
		(layer "In2.Cu")
		(net "M_B_CPU1_SA_DQ<1>")
	)
	(arc
		(start 88.998298 -278.017478)
		(mid 88.867384 -278.153838)
		(end 88.819736 -278.336756)
		(width 0.088646)
		(layer "In2.Cu")
		(net "M_B_CPU1_SA_DQ<1>")
	)
	(arc
		(start 88.528906 -278.83104)
		(mid 88.397992 -278.9674)
		(end 88.350344 -279.150318)
		(width 0.088646)
		(layer "In2.Cu")
		(net "M_B_CPU1_SA_DQ<1>")
	)
	(arc
		(start 87.880444 -279.982676)
		(mid 87.800282 -280.254865)
		(end 87.597996 -280.453846)
		(width 0.088646)
		(layer "In2.Cu")
		(net "M_B_CPU1_SA_DQ<1>")
	)
	(arc
		(start 86.470744 -280.78811)
		(mid 86.301759 -281.181374)
		(end 85.905594 -281.343354)
		(width 0.088646)
		(layer "In2.Cu")
		(net "M_B_CPU1_SA_DQ<1>")
	)
	(arc
		(start 88.350344 -279.160224)
		(mid 88.272233 -279.437173)
		(end 88.067896 -279.639776)
		(width 0.088646)
		(layer "In2.Cu")
		(net "M_B_CPU1_SA_DQ<1>")
	)
	(arc
		(start 89.290144 -277.522432)
		(mid 89.216742 -277.801282)
		(end 89.015316 -278.007572)
		(width 0.088646)
		(layer "In2.Cu")
		(net "M_B_CPU1_SA_DQ<1>")
	)
	(arc
		(start 87.032592 -280.453846)
		(mid 86.845394 -280.403703)
		(end 86.658196 -280.453846)
		(width 0.088646)
		(layer "In2.Cu")
		(net "M_B_CPU1_SA_DQ<1>")
	)
	(arc
		(start 88.059006 -279.644856)
		(mid 87.928092 -279.781216)
		(end 87.880444 -279.964134)
		(width 0.088646)
		(layer "In2.Cu")
		(net "M_B_CPU1_SA_DQ<1>")
	)
	(arc
		(start 88.820244 -276.708616)
		(mid 88.867923 -276.891516)
		(end 88.998806 -277.027894)
		(width 0.088646)
		(layer "In2.Cu")
		(net "M_B_CPU1_SA_DQ<1>")
	)
	(arc
		(start 88.819736 -278.346662)
		(mid 88.741702 -278.623548)
		(end 88.537542 -278.826214)
		(width 0.088646)
		(layer "In2.Cu")
		(net "M_B_CPU1_SA_DQ<1>")
	)
	(arc
		(start 87.597996 -280.453846)
		(mid 87.315294 -280.529588)
		(end 87.032592 -280.453846)
		(width 0.088646)
		(layer "In2.Cu")
		(net "M_B_CPU1_SA_DQ<1>")
	)
	(arc
		(start 86.649306 -280.458926)
		(mid 86.518392 -280.595286)
		(end 86.470744 -280.778204)
		(width 0.088646)
		(layer "In2.Cu")
		(net "M_B_CPU1_SA_DQ<1>")
	)
	(arc
		(start 89.007696 -277.032974)
		(mid 89.210756 -277.233783)
		(end 89.28989 -277.508208)
		(width 0.088646)
		(layer "In2.Cu")
		(net "M_B_CPU1_SA_DQ<1>")
	)
	(segment
		(start 48.277526 -295.062402)
		(end 47.882302 -295.062402)
		(width 0.20066)
		(layer "F.Cu")
		(net "M_B_CPU1_SA_DQ<19>")
	)
	(segment
		(start 44.112942 -295.06672)
		(end 42.415714 -295.06672)
		(width 0.20066)
		(layer "F.Cu")
		(net "M_B_CPU1_SA_DQ<19>")
	)
	(segment
		(start 47.753778 -295.190926)
		(end 47.753778 -295.342564)
		(width 0.20066)
		(layer "F.Cu")
		(net "M_B_CPU1_SA_DQ<19>")
	)
	(segment
		(start 44.987464 -295.491662)
		(end 44.749466 -295.491662)
		(width 0.101854)
		(layer "F.Cu")
		(net "M_B_CPU1_SA_DQ<19>")
	)
	(segment
		(start 49.143412 -295.06672)
		(end 48.935894 -295.274238)
		(width 0.20066)
		(layer "F.Cu")
		(net "M_B_CPU1_SA_DQ<19>")
	)
	(segment
		(start 47.060358 -295.491662)
		(end 44.987464 -295.491662)
		(width 0.1016)
		(layer "F.Cu")
		(net "M_B_CPU1_SA_DQ<19>")
	)
	(segment
		(start 47.753778 -295.342564)
		(end 47.60468 -295.491662)
		(width 0.20066)
		(layer "F.Cu")
		(net "M_B_CPU1_SA_DQ<19>")
	)
	(segment
		(start 44.238926 -295.363392)
		(end 44.238926 -295.192704)
		(width 0.20066)
		(layer "F.Cu")
		(net "M_B_CPU1_SA_DQ<19>")
	)
	(segment
		(start 90.604594 -266.128246)
		(end 90.604594 -265.592306)
		(width 0.20066)
		(layer "F.Cu")
		(net "M_B_CPU1_SA_DQ<19>")
	)
	(segment
		(start 44.735242 -295.505886)
		(end 44.38142 -295.505886)
		(width 0.20066)
		(layer "F.Cu")
		(net "M_B_CPU1_SA_DQ<19>")
	)
	(segment
		(start 51.089814 -295.06672)
		(end 49.959514 -295.06672)
		(width 0.20066)
		(layer "F.Cu")
		(net "M_B_CPU1_SA_DQ<19>")
	)
	(segment
		(start 47.60468 -295.491662)
		(end 47.060358 -295.491662)
		(width 0.20066)
		(layer "F.Cu")
		(net "M_B_CPU1_SA_DQ<19>")
	)
	(segment
		(start 49.959514 -295.06672)
		(end 49.143412 -295.06672)
		(width 0.20066)
		(layer "F.Cu")
		(net "M_B_CPU1_SA_DQ<19>")
	)
	(segment
		(start 44.238926 -295.192704)
		(end 44.112942 -295.06672)
		(width 0.20066)
		(layer "F.Cu")
		(net "M_B_CPU1_SA_DQ<19>")
	)
	(segment
		(start 48.489362 -295.274238)
		(end 48.277526 -295.062402)
		(width 0.20066)
		(layer "F.Cu")
		(net "M_B_CPU1_SA_DQ<19>")
	)
	(segment
		(start 44.749466 -295.491662)
		(end 44.735242 -295.505886)
		(width 0.101854)
		(layer "F.Cu")
		(net "M_B_CPU1_SA_DQ<19>")
	)
	(segment
		(start 47.882302 -295.062402)
		(end 47.753778 -295.190926)
		(width 0.20066)
		(layer "F.Cu")
		(net "M_B_CPU1_SA_DQ<19>")
	)
	(segment
		(start 90.604594 -265.592306)
		(end 90.604848 -265.592306)
		(width 0.20066)
		(layer "F.Cu")
		(net "M_B_CPU1_SA_DQ<19>")
	)
	(segment
		(start 48.935894 -295.274238)
		(end 48.489362 -295.274238)
		(width 0.20066)
		(layer "F.Cu")
		(net "M_B_CPU1_SA_DQ<19>")
	)
	(segment
		(start 44.38142 -295.505886)
		(end 44.238926 -295.363392)
		(width 0.20066)
		(layer "F.Cu")
		(net "M_B_CPU1_SA_DQ<19>")
	)
	(segment
		(start 82.973164 -267.33754)
		(end 80.921352 -269.389352)
		(width 0.18288)
		(layer "In2.Cu")
		(net "M_B_CPU1_SA_DQ<19>")
	)
	(segment
		(start 59.968892 -289.608768)
		(end 59.968892 -290.253928)
		(width 0.18288)
		(layer "In2.Cu")
		(net "M_B_CPU1_SA_DQ<19>")
	)
	(segment
		(start 66.076322 -286.036004)
		(end 65.616836 -286.49549)
		(width 0.18288)
		(layer "In2.Cu")
		(net "M_B_CPU1_SA_DQ<19>")
	)
	(segment
		(start 64.675512 -286.49549)
		(end 64.149732 -287.02127)
		(width 0.18288)
		(layer "In2.Cu")
		(net "M_B_CPU1_SA_DQ<19>")
	)
	(segment
		(start 64.149732 -287.02127)
		(end 63.485522 -287.02127)
		(width 0.18288)
		(layer "In2.Cu")
		(net "M_B_CPU1_SA_DQ<19>")
	)
	(segment
		(start 60.336938 -289.240722)
		(end 59.968892 -289.608768)
		(width 0.18288)
		(layer "In2.Cu")
		(net "M_B_CPU1_SA_DQ<19>")
	)
	(segment
		(start 88.304116 -265.877548)
		(end 88.263476 -265.899138)
		(width 0.088646)
		(layer "In2.Cu")
		(net "M_B_CPU1_SA_DQ<19>")
	)
	(segment
		(start 80.655922 -269.499334)
		(end 77.786738 -272.368518)
		(width 0.18288)
		(layer "In2.Cu")
		(net "M_B_CPU1_SA_DQ<19>")
	)
	(segment
		(start 60.795154 -291.24402)
		(end 59.723528 -291.24402)
		(width 0.18288)
		(layer "In2.Cu")
		(net "M_B_CPU1_SA_DQ<19>")
	)
	(segment
		(start 80.921352 -269.389352)
		(end 80.655922 -269.499334)
		(width 0.18288)
		(layer "In2.Cu")
		(net "M_B_CPU1_SA_DQ<19>")
	)
	(segment
		(start 71.250302 -280.592784)
		(end 66.076322 -285.766764)
		(width 0.18288)
		(layer "In2.Cu")
		(net "M_B_CPU1_SA_DQ<19>")
	)
	(segment
		(start 90.604594 -266.128246)
		(end 90.22715 -266.128246)
		(width 0.088646)
		(layer "In2.Cu")
		(net "M_B_CPU1_SA_DQ<19>")
	)
	(segment
		(start 55.919878 -293.78148)
		(end 55.919878 -294.566594)
		(width 0.18288)
		(layer "In2.Cu")
		(net "M_B_CPU1_SA_DQ<19>")
	)
	(segment
		(start 59.723528 -291.24402)
		(end 59.309 -291.658548)
		(width 0.18288)
		(layer "In2.Cu")
		(net "M_B_CPU1_SA_DQ<19>")
	)
	(segment
		(start 65.616836 -286.49549)
		(end 64.675512 -286.49549)
		(width 0.18288)
		(layer "In2.Cu")
		(net "M_B_CPU1_SA_DQ<19>")
	)
	(segment
		(start 59.309 -291.658548)
		(end 59.309 -292.774878)
		(width 0.18288)
		(layer "In2.Cu")
		(net "M_B_CPU1_SA_DQ<19>")
	)
	(segment
		(start 55.919878 -294.566594)
		(end 54.940962 -295.54551)
		(width 0.18288)
		(layer "In2.Cu")
		(net "M_B_CPU1_SA_DQ<19>")
	)
	(segment
		(start 61.612018 -288.894774)
		(end 61.612018 -289.358324)
		(width 0.18288)
		(layer "In2.Cu")
		(net "M_B_CPU1_SA_DQ<19>")
	)
	(segment
		(start 77.786738 -272.642584)
		(end 71.250302 -279.17902)
		(width 0.18288)
		(layer "In2.Cu")
		(net "M_B_CPU1_SA_DQ<19>")
	)
	(segment
		(start 60.897262 -289.240722)
		(end 60.336938 -289.240722)
		(width 0.18288)
		(layer "In2.Cu")
		(net "M_B_CPU1_SA_DQ<19>")
	)
	(segment
		(start 87.986616 -266.444222)
		(end 87.972392 -266.45235)
		(width 0.088646)
		(layer "In2.Cu")
		(net "M_B_CPU1_SA_DQ<19>")
	)
	(segment
		(start 51.568604 -295.54551)
		(end 51.089814 -295.06672)
		(width 0.18288)
		(layer "In2.Cu")
		(net "M_B_CPU1_SA_DQ<19>")
	)
	(segment
		(start 60.703206 -290.4998)
		(end 60.956698 -290.753292)
		(width 0.18288)
		(layer "In2.Cu")
		(net "M_B_CPU1_SA_DQ<19>")
	)
	(segment
		(start 60.956698 -291.082476)
		(end 60.795154 -291.24402)
		(width 0.18288)
		(layer "In2.Cu")
		(net "M_B_CPU1_SA_DQ<19>")
	)
	(segment
		(start 61.46419 -289.506152)
		(end 61.162692 -289.506152)
		(width 0.18288)
		(layer "In2.Cu")
		(net "M_B_CPU1_SA_DQ<19>")
	)
	(segment
		(start 56.733186 -292.968172)
		(end 55.919878 -293.78148)
		(width 0.18288)
		(layer "In2.Cu")
		(net "M_B_CPU1_SA_DQ<19>")
	)
	(segment
		(start 60.956698 -290.753292)
		(end 60.956698 -291.082476)
		(width 0.18288)
		(layer "In2.Cu")
		(net "M_B_CPU1_SA_DQ<19>")
	)
	(segment
		(start 66.076322 -285.766764)
		(end 66.076322 -286.036004)
		(width 0.18288)
		(layer "In2.Cu")
		(net "M_B_CPU1_SA_DQ<19>")
	)
	(segment
		(start 54.940962 -295.54551)
		(end 51.568604 -295.54551)
		(width 0.18288)
		(layer "In2.Cu")
		(net "M_B_CPU1_SA_DQ<19>")
	)
	(segment
		(start 84.49564 -266.376404)
		(end 83.9343 -266.376404)
		(width 0.088646)
		(layer "In2.Cu")
		(net "M_B_CPU1_SA_DQ<19>")
	)
	(segment
		(start 59.309 -292.774878)
		(end 59.115706 -292.968172)
		(width 0.18288)
		(layer "In2.Cu")
		(net "M_B_CPU1_SA_DQ<19>")
	)
	(segment
		(start 59.115706 -292.968172)
		(end 56.733186 -292.968172)
		(width 0.18288)
		(layer "In2.Cu")
		(net "M_B_CPU1_SA_DQ<19>")
	)
	(segment
		(start 61.162692 -289.506152)
		(end 60.897262 -289.240722)
		(width 0.18288)
		(layer "In2.Cu")
		(net "M_B_CPU1_SA_DQ<19>")
	)
	(segment
		(start 77.786738 -272.368518)
		(end 77.786738 -272.642584)
		(width 0.18288)
		(layer "In2.Cu")
		(net "M_B_CPU1_SA_DQ<19>")
	)
	(segment
		(start 61.612018 -289.358324)
		(end 61.46419 -289.506152)
		(width 0.18288)
		(layer "In2.Cu")
		(net "M_B_CPU1_SA_DQ<19>")
	)
	(segment
		(start 90.204798 -266.119102)
		(end 89.952068 -265.866372)
		(width 0.088646)
		(layer "In2.Cu")
		(net "M_B_CPU1_SA_DQ<19>")
	)
	(segment
		(start 63.485522 -287.02127)
		(end 61.612018 -288.894774)
		(width 0.18288)
		(layer "In2.Cu")
		(net "M_B_CPU1_SA_DQ<19>")
	)
	(segment
		(start 71.250302 -279.17902)
		(end 71.250302 -280.592784)
		(width 0.18288)
		(layer "In2.Cu")
		(net "M_B_CPU1_SA_DQ<19>")
	)
	(segment
		(start 59.968892 -290.253928)
		(end 60.214764 -290.4998)
		(width 0.18288)
		(layer "In2.Cu")
		(net "M_B_CPU1_SA_DQ<19>")
	)
	(segment
		(start 60.214764 -290.4998)
		(end 60.703206 -290.4998)
		(width 0.18288)
		(layer "In2.Cu")
		(net "M_B_CPU1_SA_DQ<19>")
	)
	(segment
		(start 83.9343 -266.376404)
		(end 82.973164 -267.33754)
		(width 0.088646)
		(layer "In2.Cu")
		(net "M_B_CPU1_SA_DQ<19>")
	)
	(arc
		(start 88.159844 -266.128246)
		(mid 88.113705 -266.308431)
		(end 87.986616 -266.444222)
		(width 0.088646)
		(layer "In2.Cu")
		(net "M_B_CPU1_SA_DQ<19>")
	)
	(arc
		(start 87.597996 -266.45235)
		(mid 87.315294 -266.376574)
		(end 87.032592 -266.45235)
		(width 0.088646)
		(layer "In2.Cu")
		(net "M_B_CPU1_SA_DQ<19>")
	)
	(arc
		(start 87.972392 -266.45235)
		(mid 87.785194 -266.502527)
		(end 87.597996 -266.45235)
		(width 0.088646)
		(layer "In2.Cu")
		(net "M_B_CPU1_SA_DQ<19>")
	)
	(arc
		(start 84.778596 -266.45235)
		(mid 84.642124 -266.395727)
		(end 84.49564 -266.376404)
		(width 0.088646)
		(layer "In2.Cu")
		(net "M_B_CPU1_SA_DQ<19>")
	)
	(arc
		(start 88.537796 -265.803888)
		(mid 88.424989 -265.853503)
		(end 88.304116 -265.877548)
		(width 0.088646)
		(layer "In2.Cu")
		(net "M_B_CPU1_SA_DQ<19>")
	)
	(arc
		(start 86.092792 -266.45235)
		(mid 85.905594 -266.502527)
		(end 85.718396 -266.45235)
		(width 0.088646)
		(layer "In2.Cu")
		(net "M_B_CPU1_SA_DQ<19>")
	)
	(arc
		(start 89.477596 -265.803888)
		(mid 89.194894 -265.87963)
		(end 88.912192 -265.803888)
		(width 0.088646)
		(layer "In2.Cu")
		(net "M_B_CPU1_SA_DQ<19>")
	)
	(arc
		(start 85.718396 -266.45235)
		(mid 85.435694 -266.376574)
		(end 85.152992 -266.45235)
		(width 0.088646)
		(layer "In2.Cu")
		(net "M_B_CPU1_SA_DQ<19>")
	)
	(arc
		(start 86.658196 -266.45235)
		(mid 86.375494 -266.376574)
		(end 86.092792 -266.45235)
		(width 0.088646)
		(layer "In2.Cu")
		(net "M_B_CPU1_SA_DQ<19>")
	)
	(arc
		(start 87.032592 -266.45235)
		(mid 86.845394 -266.502527)
		(end 86.658196 -266.45235)
		(width 0.088646)
		(layer "In2.Cu")
		(net "M_B_CPU1_SA_DQ<19>")
	)
	(arc
		(start 89.952068 -265.866372)
		(mid 89.725445 -265.754701)
		(end 89.477596 -265.803888)
		(width 0.088646)
		(layer "In2.Cu")
		(net "M_B_CPU1_SA_DQ<19>")
	)
	(arc
		(start 88.912192 -265.803888)
		(mid 88.724994 -265.753745)
		(end 88.537796 -265.803888)
		(width 0.088646)
		(layer "In2.Cu")
		(net "M_B_CPU1_SA_DQ<19>")
	)
	(arc
		(start 85.152992 -266.45235)
		(mid 84.965794 -266.502527)
		(end 84.778596 -266.45235)
		(width 0.088646)
		(layer "In2.Cu")
		(net "M_B_CPU1_SA_DQ<19>")
	)
	(arc
		(start 88.263476 -265.899138)
		(mid 88.186953 -266.002517)
		(end 88.159844 -266.128246)
		(width 0.088646)
		(layer "In2.Cu")
		(net "M_B_CPU1_SA_DQ<19>")
	)
	(arc
		(start 90.22715 -266.128246)
		(mid 90.215097 -266.125849)
		(end 90.204798 -266.119102)
		(width 0.088646)
		(layer "In2.Cu")
		(net "M_B_CPU1_SA_DQ<19>")
	)
	(segment
		(start 47.83709 -296.811192)
		(end 47.83709 -296.485564)
		(width 0.20066)
		(layer "F.Cu")
		(net "M_B_CPU1_SA_DQ<18>")
	)
	(segment
		(start 44.745402 -296.3418)
		(end 44.735242 -296.33164)
		(width 0.101854)
		(layer "F.Cu")
		(net "M_B_CPU1_SA_DQ<18>")
	)
	(segment
		(start 48.64481 -296.766742)
		(end 48.432974 -296.978578)
		(width 0.20066)
		(layer "F.Cu")
		(net "M_B_CPU1_SA_DQ<18>")
	)
	(segment
		(start 90.134694 -266.405868)
		(end 90.134694 -266.941808)
		(width 0.20066)
		(layer "F.Cu")
		(net "M_B_CPU1_SA_DQ<18>")
	)
	(segment
		(start 45.000418 -296.3418)
		(end 44.745402 -296.3418)
		(width 0.101854)
		(layer "F.Cu")
		(net "M_B_CPU1_SA_DQ<18>")
	)
	(segment
		(start 43.99788 -296.33164)
		(end 43.562778 -296.766742)
		(width 0.20066)
		(layer "F.Cu")
		(net "M_B_CPU1_SA_DQ<18>")
	)
	(segment
		(start 48.432974 -296.978578)
		(end 48.004476 -296.978578)
		(width 0.20066)
		(layer "F.Cu")
		(net "M_B_CPU1_SA_DQ<18>")
	)
	(segment
		(start 43.562778 -296.766742)
		(end 42.415714 -296.766742)
		(width 0.20066)
		(layer "F.Cu")
		(net "M_B_CPU1_SA_DQ<18>")
	)
	(segment
		(start 49.959514 -296.766742)
		(end 48.64481 -296.766742)
		(width 0.20066)
		(layer "F.Cu")
		(net "M_B_CPU1_SA_DQ<18>")
	)
	(segment
		(start 48.004476 -296.978578)
		(end 47.83709 -296.811192)
		(width 0.20066)
		(layer "F.Cu")
		(net "M_B_CPU1_SA_DQ<18>")
	)
	(segment
		(start 47.693326 -296.3418)
		(end 47.060358 -296.3418)
		(width 0.20066)
		(layer "F.Cu")
		(net "M_B_CPU1_SA_DQ<18>")
	)
	(segment
		(start 44.735242 -296.33164)
		(end 43.99788 -296.33164)
		(width 0.20066)
		(layer "F.Cu")
		(net "M_B_CPU1_SA_DQ<18>")
	)
	(segment
		(start 47.060358 -296.3418)
		(end 45.000418 -296.3418)
		(width 0.1016)
		(layer "F.Cu")
		(net "M_B_CPU1_SA_DQ<18>")
	)
	(segment
		(start 51.089814 -296.766742)
		(end 49.959514 -296.766742)
		(width 0.20066)
		(layer "F.Cu")
		(net "M_B_CPU1_SA_DQ<18>")
	)
	(segment
		(start 47.83709 -296.485564)
		(end 47.693326 -296.3418)
		(width 0.20066)
		(layer "F.Cu")
		(net "M_B_CPU1_SA_DQ<18>")
	)
	(segment
		(start 57.304686 -295.6814)
		(end 57.031382 -295.6814)
		(width 0.18288)
		(layer "In2.Cu")
		(net "M_B_CPU1_SA_DQ<18>")
	)
	(segment
		(start 57.957212 -296.060876)
		(end 57.684162 -296.060876)
		(width 0.18288)
		(layer "In2.Cu")
		(net "M_B_CPU1_SA_DQ<18>")
	)
	(segment
		(start 58.170826 -295.847262)
		(end 57.957212 -296.060876)
		(width 0.18288)
		(layer "In2.Cu")
		(net "M_B_CPU1_SA_DQ<18>")
	)
	(segment
		(start 67.117976 -286.17291)
		(end 67.117976 -287.211008)
		(width 0.18288)
		(layer "In2.Cu")
		(net "M_B_CPU1_SA_DQ<18>")
	)
	(segment
		(start 78.655926 -273.210528)
		(end 72.266302 -279.600152)
		(width 0.18288)
		(layer "In2.Cu")
		(net "M_B_CPU1_SA_DQ<18>")
	)
	(segment
		(start 58.369708 -295.348406)
		(end 58.170826 -295.547288)
		(width 0.18288)
		(layer "In2.Cu")
		(net "M_B_CPU1_SA_DQ<18>")
	)
	(segment
		(start 64.077342 -288.73831)
		(end 62.499494 -290.316158)
		(width 0.18288)
		(layer "In2.Cu")
		(net "M_B_CPU1_SA_DQ<18>")
	)
	(segment
		(start 56.533288 -296.568114)
		(end 55.38851 -296.568114)
		(width 0.18288)
		(layer "In2.Cu")
		(net "M_B_CPU1_SA_DQ<18>")
	)
	(segment
		(start 88.451182 -267.261086)
		(end 88.442292 -267.266166)
		(width 0.088646)
		(layer "In2.Cu")
		(net "M_B_CPU1_SA_DQ<18>")
	)
	(segment
		(start 72.266302 -279.600152)
		(end 72.266302 -281.024584)
		(width 0.18288)
		(layer "In2.Cu")
		(net "M_B_CPU1_SA_DQ<18>")
	)
	(segment
		(start 55.38851 -296.568114)
		(end 54.72303 -297.233594)
		(width 0.18288)
		(layer "In2.Cu")
		(net "M_B_CPU1_SA_DQ<18>")
	)
	(segment
		(start 58.170826 -295.547288)
		(end 58.170826 -295.847262)
		(width 0.18288)
		(layer "In2.Cu")
		(net "M_B_CPU1_SA_DQ<18>")
	)
	(segment
		(start 57.684162 -296.060876)
		(end 57.304686 -295.6814)
		(width 0.18288)
		(layer "In2.Cu")
		(net "M_B_CPU1_SA_DQ<18>")
	)
	(segment
		(start 84.495894 -267.316966)
		(end 83.97113 -267.316966)
		(width 0.088646)
		(layer "In2.Cu")
		(net "M_B_CPU1_SA_DQ<18>")
	)
	(segment
		(start 61.903102 -293.291768)
		(end 61.903102 -293.577772)
		(width 0.18288)
		(layer "In2.Cu")
		(net "M_B_CPU1_SA_DQ<18>")
	)
	(segment
		(start 54.311042 -297.233594)
		(end 54.015894 -296.938446)
		(width 0.18288)
		(layer "In2.Cu")
		(net "M_B_CPU1_SA_DQ<18>")
	)
	(segment
		(start 59.982862 -293.798752)
		(end 59.343036 -294.438578)
		(width 0.18288)
		(layer "In2.Cu")
		(net "M_B_CPU1_SA_DQ<18>")
	)
	(segment
		(start 66.571368 -288.531046)
		(end 66.26098 -288.73831)
		(width 0.18288)
		(layer "In2.Cu")
		(net "M_B_CPU1_SA_DQ<18>")
	)
	(segment
		(start 66.26098 -288.73831)
		(end 64.077342 -288.73831)
		(width 0.18288)
		(layer "In2.Cu")
		(net "M_B_CPU1_SA_DQ<18>")
	)
	(segment
		(start 62.499494 -290.316158)
		(end 62.499494 -292.695376)
		(width 0.18288)
		(layer "In2.Cu")
		(net "M_B_CPU1_SA_DQ<18>")
	)
	(segment
		(start 83.97113 -267.316966)
		(end 83.46186 -267.826236)
		(width 0.088646)
		(layer "In2.Cu")
		(net "M_B_CPU1_SA_DQ<18>")
	)
	(segment
		(start 52.844954 -296.938446)
		(end 52.31384 -297.46956)
		(width 0.18288)
		(layer "In2.Cu")
		(net "M_B_CPU1_SA_DQ<18>")
	)
	(segment
		(start 61.682122 -293.798752)
		(end 59.982862 -293.798752)
		(width 0.18288)
		(layer "In2.Cu")
		(net "M_B_CPU1_SA_DQ<18>")
	)
	(segment
		(start 72.266302 -281.024584)
		(end 67.117976 -286.17291)
		(width 0.18288)
		(layer "In2.Cu")
		(net "M_B_CPU1_SA_DQ<18>")
	)
	(segment
		(start 62.499494 -292.695376)
		(end 61.903102 -293.291768)
		(width 0.18288)
		(layer "In2.Cu")
		(net "M_B_CPU1_SA_DQ<18>")
	)
	(segment
		(start 56.834024 -296.267378)
		(end 56.533288 -296.568114)
		(width 0.18288)
		(layer "In2.Cu")
		(net "M_B_CPU1_SA_DQ<18>")
	)
	(segment
		(start 57.031382 -295.6814)
		(end 56.834024 -295.878758)
		(width 0.18288)
		(layer "In2.Cu")
		(net "M_B_CPU1_SA_DQ<18>")
	)
	(segment
		(start 59.149742 -295.348406)
		(end 58.369708 -295.348406)
		(width 0.18288)
		(layer "In2.Cu")
		(net "M_B_CPU1_SA_DQ<18>")
	)
	(segment
		(start 59.343036 -294.438578)
		(end 59.343036 -295.155112)
		(width 0.18288)
		(layer "In2.Cu")
		(net "M_B_CPU1_SA_DQ<18>")
	)
	(segment
		(start 54.72303 -297.233594)
		(end 54.311042 -297.233594)
		(width 0.18288)
		(layer "In2.Cu")
		(net "M_B_CPU1_SA_DQ<18>")
	)
	(segment
		(start 67.117976 -287.211008)
		(end 66.571368 -288.531046)
		(width 0.18288)
		(layer "In2.Cu")
		(net "M_B_CPU1_SA_DQ<18>")
	)
	(segment
		(start 59.343036 -295.155112)
		(end 59.149742 -295.348406)
		(width 0.18288)
		(layer "In2.Cu")
		(net "M_B_CPU1_SA_DQ<18>")
	)
	(segment
		(start 83.46186 -267.826236)
		(end 78.655926 -272.63217)
		(width 0.18288)
		(layer "In2.Cu")
		(net "M_B_CPU1_SA_DQ<18>")
	)
	(segment
		(start 56.834024 -295.878758)
		(end 56.834024 -296.267378)
		(width 0.18288)
		(layer "In2.Cu")
		(net "M_B_CPU1_SA_DQ<18>")
	)
	(segment
		(start 89.821766 -266.941808)
		(end 89.756488 -266.87653)
		(width 0.088646)
		(layer "In2.Cu")
		(net "M_B_CPU1_SA_DQ<18>")
	)
	(segment
		(start 90.134694 -266.941808)
		(end 89.821766 -266.941808)
		(width 0.088646)
		(layer "In2.Cu")
		(net "M_B_CPU1_SA_DQ<18>")
	)
	(segment
		(start 52.31384 -297.46956)
		(end 51.792632 -297.46956)
		(width 0.18288)
		(layer "In2.Cu")
		(net "M_B_CPU1_SA_DQ<18>")
	)
	(segment
		(start 61.903102 -293.577772)
		(end 61.682122 -293.798752)
		(width 0.18288)
		(layer "In2.Cu")
		(net "M_B_CPU1_SA_DQ<18>")
	)
	(segment
		(start 78.655926 -272.63217)
		(end 78.655926 -273.210528)
		(width 0.18288)
		(layer "In2.Cu")
		(net "M_B_CPU1_SA_DQ<18>")
	)
	(segment
		(start 51.792632 -297.46956)
		(end 51.089814 -296.766742)
		(width 0.18288)
		(layer "In2.Cu")
		(net "M_B_CPU1_SA_DQ<18>")
	)
	(segment
		(start 88.629744 -266.931902)
		(end 88.629744 -266.941808)
		(width 0.088646)
		(layer "In2.Cu")
		(net "M_B_CPU1_SA_DQ<18>")
	)
	(segment
		(start 54.015894 -296.938446)
		(end 52.844954 -296.938446)
		(width 0.18288)
		(layer "In2.Cu")
		(net "M_B_CPU1_SA_DQ<18>")
	)
	(arc
		(start 89.756488 -266.87653)
		(mid 89.667359 -266.631355)
		(end 89.477596 -266.45235)
		(width 0.088646)
		(layer "In2.Cu")
		(net "M_B_CPU1_SA_DQ<18>")
	)
	(arc
		(start 86.188296 -267.266166)
		(mid 85.905594 -267.190424)
		(end 85.622892 -267.266166)
		(width 0.088646)
		(layer "In2.Cu")
		(net "M_B_CPU1_SA_DQ<18>")
	)
	(arc
		(start 84.683092 -267.266166)
		(mid 84.592831 -267.303863)
		(end 84.495894 -267.316966)
		(width 0.088646)
		(layer "In2.Cu")
		(net "M_B_CPU1_SA_DQ<18>")
	)
	(arc
		(start 85.622892 -267.266166)
		(mid 85.435694 -267.316309)
		(end 85.248496 -267.266166)
		(width 0.088646)
		(layer "In2.Cu")
		(net "M_B_CPU1_SA_DQ<18>")
	)
	(arc
		(start 86.562692 -267.266166)
		(mid 86.375494 -267.316309)
		(end 86.188296 -267.266166)
		(width 0.088646)
		(layer "In2.Cu")
		(net "M_B_CPU1_SA_DQ<18>")
	)
	(arc
		(start 87.502492 -267.266166)
		(mid 87.315294 -267.316309)
		(end 87.128096 -267.266166)
		(width 0.088646)
		(layer "In2.Cu")
		(net "M_B_CPU1_SA_DQ<18>")
	)
	(arc
		(start 88.629744 -266.941808)
		(mid 88.582065 -267.124708)
		(end 88.451182 -267.261086)
		(width 0.088646)
		(layer "In2.Cu")
		(net "M_B_CPU1_SA_DQ<18>")
	)
	(arc
		(start 87.128096 -267.266166)
		(mid 86.845394 -267.190424)
		(end 86.562692 -267.266166)
		(width 0.088646)
		(layer "In2.Cu")
		(net "M_B_CPU1_SA_DQ<18>")
	)
	(arc
		(start 88.912192 -266.45235)
		(mid 88.707857 -266.654955)
		(end 88.629744 -266.931902)
		(width 0.088646)
		(layer "In2.Cu")
		(net "M_B_CPU1_SA_DQ<18>")
	)
	(arc
		(start 85.248496 -267.266166)
		(mid 84.965794 -267.190424)
		(end 84.683092 -267.266166)
		(width 0.088646)
		(layer "In2.Cu")
		(net "M_B_CPU1_SA_DQ<18>")
	)
	(arc
		(start 89.477596 -266.45235)
		(mid 89.194894 -266.376574)
		(end 88.912192 -266.45235)
		(width 0.088646)
		(layer "In2.Cu")
		(net "M_B_CPU1_SA_DQ<18>")
	)
	(arc
		(start 88.067896 -267.266166)
		(mid 87.785194 -267.190424)
		(end 87.502492 -267.266166)
		(width 0.088646)
		(layer "In2.Cu")
		(net "M_B_CPU1_SA_DQ<18>")
	)
	(arc
		(start 88.442292 -267.266166)
		(mid 88.255094 -267.316309)
		(end 88.067896 -267.266166)
		(width 0.088646)
		(layer "In2.Cu")
		(net "M_B_CPU1_SA_DQ<18>")
	)
	(segment
		(start 40.36568 -296.127932)
		(end 39.861236 -296.127932)
		(width 0.20066)
		(layer "F.Cu")
		(net "M_B_CPU1_SA_DQ<17>")
	)
	(segment
		(start 88.724994 -265.592306)
		(end 88.725248 -265.592306)
		(width 0.20066)
		(layer "F.Cu")
		(net "M_B_CPU1_SA_DQ<17>")
	)
	(segment
		(start 44.22013 -295.916604)
		(end 43.795188 -295.491662)
		(width 0.20066)
		(layer "F.Cu")
		(net "M_B_CPU1_SA_DQ<17>")
	)
	(segment
		(start 39.861236 -296.127932)
		(end 39.649908 -295.916604)
		(width 0.20066)
		(layer "F.Cu")
		(net "M_B_CPU1_SA_DQ<17>")
	)
	(segment
		(start 88.724994 -266.128246)
		(end 88.724994 -265.592306)
		(width 0.20066)
		(layer "F.Cu")
		(net "M_B_CPU1_SA_DQ<17>")
	)
	(segment
		(start 43.795188 -295.491662)
		(end 43.616626 -295.491662)
		(width 0.20066)
		(layer "F.Cu")
		(net "M_B_CPU1_SA_DQ<17>")
	)
	(segment
		(start 43.616626 -295.491662)
		(end 43.285918 -295.491662)
		(width 0.101854)
		(layer "F.Cu")
		(net "M_B_CPU1_SA_DQ<17>")
	)
	(segment
		(start 40.682672 -295.482772)
		(end 40.520112 -295.645332)
		(width 0.20066)
		(layer "F.Cu")
		(net "M_B_CPU1_SA_DQ<17>")
	)
	(segment
		(start 40.520112 -295.9735)
		(end 40.36568 -296.127932)
		(width 0.20066)
		(layer "F.Cu")
		(net "M_B_CPU1_SA_DQ<17>")
	)
	(segment
		(start 43.285918 -295.491662)
		(end 41.3004 -295.491662)
		(width 0.1016)
		(layer "F.Cu")
		(net "M_B_CPU1_SA_DQ<17>")
	)
	(segment
		(start 46.964346 -295.916604)
		(end 45.859446 -295.916604)
		(width 0.20066)
		(layer "F.Cu")
		(net "M_B_CPU1_SA_DQ<17>")
	)
	(segment
		(start 40.520112 -295.645332)
		(end 40.520112 -295.9735)
		(width 0.20066)
		(layer "F.Cu")
		(net "M_B_CPU1_SA_DQ<17>")
	)
	(segment
		(start 39.649908 -295.916604)
		(end 38.315646 -295.916604)
		(width 0.20066)
		(layer "F.Cu")
		(net "M_B_CPU1_SA_DQ<17>")
	)
	(segment
		(start 45.859446 -295.916604)
		(end 44.22013 -295.916604)
		(width 0.20066)
		(layer "F.Cu")
		(net "M_B_CPU1_SA_DQ<17>")
	)
	(segment
		(start 41.29151 -295.482772)
		(end 40.682672 -295.482772)
		(width 0.20066)
		(layer "F.Cu")
		(net "M_B_CPU1_SA_DQ<17>")
	)
	(segment
		(start 41.3004 -295.491662)
		(end 41.29151 -295.482772)
		(width 0.1016)
		(layer "F.Cu")
		(net "M_B_CPU1_SA_DQ<17>")
	)
	(segment
		(start 51.524916 -296.186098)
		(end 51.369214 -296.3418)
		(width 0.18288)
		(layer "In2.Cu")
		(net "M_B_CPU1_SA_DQ<17>")
	)
	(segment
		(start 56.65089 -294.60571)
		(end 55.15229 -296.10431)
		(width 0.18288)
		(layer "In2.Cu")
		(net "M_B_CPU1_SA_DQ<17>")
	)
	(segment
		(start 83.217512 -267.581888)
		(end 78.26375 -272.53565)
		(width 0.18288)
		(layer "In2.Cu")
		(net "M_B_CPU1_SA_DQ<17>")
	)
	(segment
		(start 71.758302 -279.389586)
		(end 71.758302 -280.806398)
		(width 0.18288)
		(layer "In2.Cu")
		(net "M_B_CPU1_SA_DQ<17>")
	)
	(segment
		(start 61.989208 -291.86378)
		(end 61.737748 -292.11524)
		(width 0.18288)
		(layer "In2.Cu")
		(net "M_B_CPU1_SA_DQ<17>")
	)
	(segment
		(start 54.44109 -296.10431)
		(end 54.222396 -296.323004)
		(width 0.18288)
		(layer "In2.Cu")
		(net "M_B_CPU1_SA_DQ<17>")
	)
	(segment
		(start 49.170336 -296.281094)
		(end 48.889412 -296.562018)
		(width 0.18288)
		(layer "In2.Cu")
		(net "M_B_CPU1_SA_DQ<17>")
	)
	(segment
		(start 61.563758 -291.034978)
		(end 61.989208 -291.460428)
		(width 0.18288)
		(layer "In2.Cu")
		(net "M_B_CPU1_SA_DQ<17>")
	)
	(segment
		(start 52.399438 -296.186098)
		(end 51.524916 -296.186098)
		(width 0.18288)
		(layer "In2.Cu")
		(net "M_B_CPU1_SA_DQ<17>")
	)
	(segment
		(start 71.758302 -280.806398)
		(end 66.608198 -285.956502)
		(width 0.18288)
		(layer "In2.Cu")
		(net "M_B_CPU1_SA_DQ<17>")
	)
	(segment
		(start 55.15229 -296.10431)
		(end 54.44109 -296.10431)
		(width 0.18288)
		(layer "In2.Cu")
		(net "M_B_CPU1_SA_DQ<17>")
	)
	(segment
		(start 88.724994 -266.128246)
		(end 88.229694 -266.477242)
		(width 0.088646)
		(layer "In2.Cu")
		(net "M_B_CPU1_SA_DQ<17>")
	)
	(segment
		(start 51.369214 -296.3418)
		(end 50.776886 -296.3418)
		(width 0.18288)
		(layer "In2.Cu")
		(net "M_B_CPU1_SA_DQ<17>")
	)
	(segment
		(start 61.737748 -292.11524)
		(end 60.719716 -292.11524)
		(width 0.18288)
		(layer "In2.Cu")
		(net "M_B_CPU1_SA_DQ<17>")
	)
	(segment
		(start 63.619888 -287.801558)
		(end 62.545214 -288.876232)
		(width 0.18288)
		(layer "In2.Cu")
		(net "M_B_CPU1_SA_DQ<17>")
	)
	(segment
		(start 84.49564 -266.56665)
		(end 84.23275 -266.56665)
		(width 0.088646)
		(layer "In2.Cu")
		(net "M_B_CPU1_SA_DQ<17>")
	)
	(segment
		(start 59.325256 -293.704772)
		(end 58.475372 -293.704772)
		(width 0.18288)
		(layer "In2.Cu")
		(net "M_B_CPU1_SA_DQ<17>")
	)
	(segment
		(start 66.608198 -287.079944)
		(end 65.886584 -287.801558)
		(width 0.18288)
		(layer "In2.Cu")
		(net "M_B_CPU1_SA_DQ<17>")
	)
	(segment
		(start 84.23275 -266.56665)
		(end 83.217512 -267.581888)
		(width 0.088646)
		(layer "In2.Cu")
		(net "M_B_CPU1_SA_DQ<17>")
	)
	(segment
		(start 52.536344 -296.323004)
		(end 52.399438 -296.186098)
		(width 0.18288)
		(layer "In2.Cu")
		(net "M_B_CPU1_SA_DQ<17>")
	)
	(segment
		(start 50.71618 -296.281094)
		(end 49.170336 -296.281094)
		(width 0.18288)
		(layer "In2.Cu")
		(net "M_B_CPU1_SA_DQ<17>")
	)
	(segment
		(start 61.989208 -291.460428)
		(end 61.989208 -291.86378)
		(width 0.18288)
		(layer "In2.Cu")
		(net "M_B_CPU1_SA_DQ<17>")
	)
	(segment
		(start 48.889412 -296.562018)
		(end 47.60976 -296.562018)
		(width 0.18288)
		(layer "In2.Cu")
		(net "M_B_CPU1_SA_DQ<17>")
	)
	(segment
		(start 60.719716 -292.11524)
		(end 60.576206 -292.25875)
		(width 0.18288)
		(layer "In2.Cu")
		(net "M_B_CPU1_SA_DQ<17>")
	)
	(segment
		(start 65.886584 -287.801558)
		(end 63.619888 -287.801558)
		(width 0.18288)
		(layer "In2.Cu")
		(net "M_B_CPU1_SA_DQ<17>")
	)
	(segment
		(start 66.608198 -285.956502)
		(end 66.608198 -287.079944)
		(width 0.18288)
		(layer "In2.Cu")
		(net "M_B_CPU1_SA_DQ<17>")
	)
	(segment
		(start 50.776886 -296.3418)
		(end 50.71618 -296.281094)
		(width 0.18288)
		(layer "In2.Cu")
		(net "M_B_CPU1_SA_DQ<17>")
	)
	(segment
		(start 57.574434 -294.60571)
		(end 56.65089 -294.60571)
		(width 0.18288)
		(layer "In2.Cu")
		(net "M_B_CPU1_SA_DQ<17>")
	)
	(segment
		(start 61.563758 -290.526216)
		(end 61.563758 -291.034978)
		(width 0.18288)
		(layer "In2.Cu")
		(net "M_B_CPU1_SA_DQ<17>")
	)
	(segment
		(start 62.545214 -288.876232)
		(end 62.545214 -289.54476)
		(width 0.18288)
		(layer "In2.Cu")
		(net "M_B_CPU1_SA_DQ<17>")
	)
	(segment
		(start 60.576206 -292.25875)
		(end 60.576206 -292.453822)
		(width 0.18288)
		(layer "In2.Cu")
		(net "M_B_CPU1_SA_DQ<17>")
	)
	(segment
		(start 58.475372 -293.704772)
		(end 57.574434 -294.60571)
		(width 0.18288)
		(layer "In2.Cu")
		(net "M_B_CPU1_SA_DQ<17>")
	)
	(segment
		(start 78.26375 -272.884138)
		(end 71.758302 -279.389586)
		(width 0.18288)
		(layer "In2.Cu")
		(net "M_B_CPU1_SA_DQ<17>")
	)
	(segment
		(start 62.545214 -289.54476)
		(end 61.563758 -290.526216)
		(width 0.18288)
		(layer "In2.Cu")
		(net "M_B_CPU1_SA_DQ<17>")
	)
	(segment
		(start 54.222396 -296.323004)
		(end 52.536344 -296.323004)
		(width 0.18288)
		(layer "In2.Cu")
		(net "M_B_CPU1_SA_DQ<17>")
	)
	(segment
		(start 60.576206 -292.453822)
		(end 59.325256 -293.704772)
		(width 0.18288)
		(layer "In2.Cu")
		(net "M_B_CPU1_SA_DQ<17>")
	)
	(segment
		(start 78.26375 -272.53565)
		(end 78.26375 -272.884138)
		(width 0.18288)
		(layer "In2.Cu")
		(net "M_B_CPU1_SA_DQ<17>")
	)
	(segment
		(start 47.60976 -296.562018)
		(end 46.964346 -295.916604)
		(width 0.18288)
		(layer "In2.Cu")
		(net "M_B_CPU1_SA_DQ<17>")
	)
	(arc
		(start 86.188296 -266.617704)
		(mid 85.905594 -266.69348)
		(end 85.622892 -266.617704)
		(width 0.088646)
		(layer "In2.Cu")
		(net "M_B_CPU1_SA_DQ<17>")
	)
	(arc
		(start 85.622892 -266.617704)
		(mid 85.435694 -266.567527)
		(end 85.248496 -266.617704)
		(width 0.088646)
		(layer "In2.Cu")
		(net "M_B_CPU1_SA_DQ<17>")
	)
	(arc
		(start 84.683092 -266.617704)
		(mid 84.592726 -266.579862)
		(end 84.49564 -266.56665)
		(width 0.088646)
		(layer "In2.Cu")
		(net "M_B_CPU1_SA_DQ<17>")
	)
	(arc
		(start 88.067896 -266.617704)
		(mid 87.785194 -266.69348)
		(end 87.502492 -266.617704)
		(width 0.088646)
		(layer "In2.Cu")
		(net "M_B_CPU1_SA_DQ<17>")
	)
	(arc
		(start 87.128096 -266.617704)
		(mid 86.845394 -266.69348)
		(end 86.562692 -266.617704)
		(width 0.088646)
		(layer "In2.Cu")
		(net "M_B_CPU1_SA_DQ<17>")
	)
	(arc
		(start 85.248496 -266.617704)
		(mid 84.965794 -266.69348)
		(end 84.683092 -266.617704)
		(width 0.088646)
		(layer "In2.Cu")
		(net "M_B_CPU1_SA_DQ<17>")
	)
	(arc
		(start 87.502492 -266.617704)
		(mid 87.315294 -266.567527)
		(end 87.128096 -266.617704)
		(width 0.088646)
		(layer "In2.Cu")
		(net "M_B_CPU1_SA_DQ<17>")
	)
	(arc
		(start 88.229694 -266.477242)
		(mid 88.155523 -266.555226)
		(end 88.067896 -266.617704)
		(width 0.088646)
		(layer "In2.Cu")
		(net "M_B_CPU1_SA_DQ<17>")
	)
	(arc
		(start 86.562692 -266.617704)
		(mid 86.375494 -266.567527)
		(end 86.188296 -266.617704)
		(width 0.088646)
		(layer "In2.Cu")
		(net "M_B_CPU1_SA_DQ<17>")
	)
	(segment
		(start 40.520112 -297.393106)
		(end 40.520112 -297.682666)
		(width 0.20066)
		(layer "F.Cu")
		(net "M_B_CPU1_SA_DQ<16>")
	)
	(segment
		(start 41.299638 -297.191684)
		(end 41.29151 -297.183556)
		(width 0.101854)
		(layer "F.Cu")
		(net "M_B_CPU1_SA_DQ<16>")
	)
	(segment
		(start 41.29151 -297.183556)
		(end 40.729662 -297.183556)
		(width 0.20066)
		(layer "F.Cu")
		(net "M_B_CPU1_SA_DQ<16>")
	)
	(segment
		(start 39.888668 -297.855386)
		(end 39.649908 -297.616626)
		(width 0.20066)
		(layer "F.Cu")
		(net "M_B_CPU1_SA_DQ<16>")
	)
	(segment
		(start 39.649908 -297.616626)
		(end 38.315646 -297.616626)
		(width 0.20066)
		(layer "F.Cu")
		(net "M_B_CPU1_SA_DQ<16>")
	)
	(segment
		(start 40.520112 -297.682666)
		(end 40.347392 -297.855386)
		(width 0.20066)
		(layer "F.Cu")
		(net "M_B_CPU1_SA_DQ<16>")
	)
	(segment
		(start 44.490386 -297.616626)
		(end 44.065444 -297.191684)
		(width 0.20066)
		(layer "F.Cu")
		(net "M_B_CPU1_SA_DQ<16>")
	)
	(segment
		(start 40.347392 -297.855386)
		(end 39.888668 -297.855386)
		(width 0.20066)
		(layer "F.Cu")
		(net "M_B_CPU1_SA_DQ<16>")
	)
	(segment
		(start 44.065444 -297.191684)
		(end 43.616626 -297.191684)
		(width 0.20066)
		(layer "F.Cu")
		(net "M_B_CPU1_SA_DQ<16>")
	)
	(segment
		(start 40.729662 -297.183556)
		(end 40.520112 -297.393106)
		(width 0.20066)
		(layer "F.Cu")
		(net "M_B_CPU1_SA_DQ<16>")
	)
	(segment
		(start 41.547542 -297.191684)
		(end 41.299638 -297.191684)
		(width 0.101854)
		(layer "F.Cu")
		(net "M_B_CPU1_SA_DQ<16>")
	)
	(segment
		(start 43.616626 -297.191684)
		(end 41.547542 -297.191684)
		(width 0.1016)
		(layer "F.Cu")
		(net "M_B_CPU1_SA_DQ<16>")
	)
	(segment
		(start 45.859446 -297.616626)
		(end 44.490386 -297.616626)
		(width 0.20066)
		(layer "F.Cu")
		(net "M_B_CPU1_SA_DQ<16>")
	)
	(segment
		(start 46.964346 -297.616626)
		(end 45.859446 -297.616626)
		(width 0.20066)
		(layer "F.Cu")
		(net "M_B_CPU1_SA_DQ<16>")
	)
	(segment
		(start 89.194894 -266.405868)
		(end 89.194894 -266.941808)
		(width 0.20066)
		(layer "F.Cu")
		(net "M_B_CPU1_SA_DQ<16>")
	)
	(segment
		(start 83.706208 -268.070838)
		(end 79.002636 -272.77441)
		(width 0.18288)
		(layer "In2.Cu")
		(net "M_B_CPU1_SA_DQ<16>")
	)
	(segment
		(start 84.495894 -267.507212)
		(end 84.269834 -267.507212)
		(width 0.088646)
		(layer "In2.Cu")
		(net "M_B_CPU1_SA_DQ<16>")
	)
	(segment
		(start 79.002636 -272.77441)
		(end 79.002636 -273.582638)
		(width 0.18288)
		(layer "In2.Cu")
		(net "M_B_CPU1_SA_DQ<16>")
	)
	(segment
		(start 89.194894 -266.941808)
		(end 89.507822 -266.941808)
		(width 0.088646)
		(layer "In2.Cu")
		(net "M_B_CPU1_SA_DQ<16>")
	)
	(segment
		(start 64.328802 -290.217606)
		(end 63.903606 -290.642802)
		(width 0.18288)
		(layer "In2.Cu")
		(net "M_B_CPU1_SA_DQ<16>")
	)
	(segment
		(start 61.735208 -294.633142)
		(end 60.796678 -295.021762)
		(width 0.18288)
		(layer "In2.Cu")
		(net "M_B_CPU1_SA_DQ<16>")
	)
	(segment
		(start 72.77481 -279.810464)
		(end 72.77481 -281.247596)
		(width 0.18288)
		(layer "In2.Cu")
		(net "M_B_CPU1_SA_DQ<16>")
	)
	(segment
		(start 67.005708 -288.862008)
		(end 66.03365 -289.511486)
		(width 0.18288)
		(layer "In2.Cu")
		(net "M_B_CPU1_SA_DQ<16>")
	)
	(segment
		(start 62.910212 -293.040562)
		(end 62.069218 -294.299132)
		(width 0.18288)
		(layer "In2.Cu")
		(net "M_B_CPU1_SA_DQ<16>")
	)
	(segment
		(start 89.007696 -266.617704)
		(end 88.993472 -266.625832)
		(width 0.088646)
		(layer "In2.Cu")
		(net "M_B_CPU1_SA_DQ<16>")
	)
	(segment
		(start 58.23331 -297.180762)
		(end 56.1975 -297.180762)
		(width 0.18288)
		(layer "In2.Cu")
		(net "M_B_CPU1_SA_DQ<16>")
	)
	(segment
		(start 66.03365 -289.511486)
		(end 64.328802 -290.217606)
		(width 0.18288)
		(layer "In2.Cu")
		(net "M_B_CPU1_SA_DQ<16>")
	)
	(segment
		(start 49.10582 -298.041822)
		(end 48.951896 -298.195746)
		(width 0.18288)
		(layer "In2.Cu")
		(net "M_B_CPU1_SA_DQ<16>")
	)
	(segment
		(start 68.310252 -285.712154)
		(end 67.005708 -288.862008)
		(width 0.18288)
		(layer "In2.Cu")
		(net "M_B_CPU1_SA_DQ<16>")
	)
	(segment
		(start 60.796678 -295.021762)
		(end 60.084208 -295.497758)
		(width 0.18288)
		(layer "In2.Cu")
		(net "M_B_CPU1_SA_DQ<16>")
	)
	(segment
		(start 89.396316 -266.625832)
		(end 89.382092 -266.617704)
		(width 0.088646)
		(layer "In2.Cu")
		(net "M_B_CPU1_SA_DQ<16>")
	)
	(segment
		(start 79.002636 -273.582638)
		(end 72.77481 -279.810464)
		(width 0.18288)
		(layer "In2.Cu")
		(net "M_B_CPU1_SA_DQ<16>")
	)
	(segment
		(start 48.362616 -298.195746)
		(end 46.964346 -297.616626)
		(width 0.18288)
		(layer "In2.Cu")
		(net "M_B_CPU1_SA_DQ<16>")
	)
	(segment
		(start 51.73345 -297.99153)
		(end 51.683158 -298.041822)
		(width 0.18288)
		(layer "In2.Cu")
		(net "M_B_CPU1_SA_DQ<16>")
	)
	(segment
		(start 60.084208 -295.497758)
		(end 59.21502 -296.366946)
		(width 0.18288)
		(layer "In2.Cu")
		(net "M_B_CPU1_SA_DQ<16>")
	)
	(segment
		(start 54.24043 -297.99153)
		(end 51.73345 -297.99153)
		(width 0.18288)
		(layer "In2.Cu")
		(net "M_B_CPU1_SA_DQ<16>")
	)
	(segment
		(start 59.21502 -296.366946)
		(end 58.23331 -297.180762)
		(width 0.18288)
		(layer "In2.Cu")
		(net "M_B_CPU1_SA_DQ<16>")
	)
	(segment
		(start 88.820244 -266.941808)
		(end 88.820244 -266.96035)
		(width 0.088646)
		(layer "In2.Cu")
		(net "M_B_CPU1_SA_DQ<16>")
	)
	(segment
		(start 72.77481 -281.247596)
		(end 68.310252 -285.712154)
		(width 0.18288)
		(layer "In2.Cu")
		(net "M_B_CPU1_SA_DQ<16>")
	)
	(segment
		(start 51.683158 -298.041822)
		(end 49.10582 -298.041822)
		(width 0.18288)
		(layer "In2.Cu")
		(net "M_B_CPU1_SA_DQ<16>")
	)
	(segment
		(start 84.269834 -267.507212)
		(end 83.706208 -268.070838)
		(width 0.088646)
		(layer "In2.Cu")
		(net "M_B_CPU1_SA_DQ<16>")
	)
	(segment
		(start 62.069218 -294.299132)
		(end 61.735208 -294.633142)
		(width 0.18288)
		(layer "In2.Cu")
		(net "M_B_CPU1_SA_DQ<16>")
	)
	(segment
		(start 89.507822 -266.941808)
		(end 89.564972 -266.884658)
		(width 0.088646)
		(layer "In2.Cu")
		(net "M_B_CPU1_SA_DQ<16>")
	)
	(segment
		(start 56.1975 -297.180762)
		(end 54.24043 -297.99153)
		(width 0.18288)
		(layer "In2.Cu")
		(net "M_B_CPU1_SA_DQ<16>")
	)
	(segment
		(start 63.903606 -290.642802)
		(end 62.910212 -293.040562)
		(width 0.18288)
		(layer "In2.Cu")
		(net "M_B_CPU1_SA_DQ<16>")
	)
	(segment
		(start 48.951896 -298.195746)
		(end 48.362616 -298.195746)
		(width 0.18288)
		(layer "In2.Cu")
		(net "M_B_CPU1_SA_DQ<16>")
	)
	(arc
		(start 87.972392 -267.43152)
		(mid 87.785194 -267.381377)
		(end 87.597996 -267.43152)
		(width 0.088646)
		(layer "In2.Cu")
		(net "M_B_CPU1_SA_DQ<16>")
	)
	(arc
		(start 89.382092 -266.617704)
		(mid 89.194894 -266.567527)
		(end 89.007696 -266.617704)
		(width 0.088646)
		(layer "In2.Cu")
		(net "M_B_CPU1_SA_DQ<16>")
	)
	(arc
		(start 88.537796 -267.43152)
		(mid 88.255094 -267.507262)
		(end 87.972392 -267.43152)
		(width 0.088646)
		(layer "In2.Cu")
		(net "M_B_CPU1_SA_DQ<16>")
	)
	(arc
		(start 87.597996 -267.43152)
		(mid 87.315294 -267.507262)
		(end 87.032592 -267.43152)
		(width 0.088646)
		(layer "In2.Cu")
		(net "M_B_CPU1_SA_DQ<16>")
	)
	(arc
		(start 89.564972 -266.884658)
		(mid 89.508577 -266.737038)
		(end 89.396316 -266.625832)
		(width 0.088646)
		(layer "In2.Cu")
		(net "M_B_CPU1_SA_DQ<16>")
	)
	(arc
		(start 86.092792 -267.43152)
		(mid 85.905594 -267.381377)
		(end 85.718396 -267.43152)
		(width 0.088646)
		(layer "In2.Cu")
		(net "M_B_CPU1_SA_DQ<16>")
	)
	(arc
		(start 85.152992 -267.43152)
		(mid 84.965794 -267.381377)
		(end 84.778596 -267.43152)
		(width 0.088646)
		(layer "In2.Cu")
		(net "M_B_CPU1_SA_DQ<16>")
	)
	(arc
		(start 84.778596 -267.43152)
		(mid 84.642226 -267.487973)
		(end 84.495894 -267.507212)
		(width 0.088646)
		(layer "In2.Cu")
		(net "M_B_CPU1_SA_DQ<16>")
	)
	(arc
		(start 85.718396 -267.43152)
		(mid 85.435694 -267.507262)
		(end 85.152992 -267.43152)
		(width 0.088646)
		(layer "In2.Cu")
		(net "M_B_CPU1_SA_DQ<16>")
	)
	(arc
		(start 87.032592 -267.43152)
		(mid 86.845394 -267.381377)
		(end 86.658196 -267.43152)
		(width 0.088646)
		(layer "In2.Cu")
		(net "M_B_CPU1_SA_DQ<16>")
	)
	(arc
		(start 88.820244 -266.96035)
		(mid 88.740082 -267.232539)
		(end 88.537796 -267.43152)
		(width 0.088646)
		(layer "In2.Cu")
		(net "M_B_CPU1_SA_DQ<16>")
	)
	(arc
		(start 86.658196 -267.43152)
		(mid 86.375494 -267.507262)
		(end 86.092792 -267.43152)
		(width 0.088646)
		(layer "In2.Cu")
		(net "M_B_CPU1_SA_DQ<16>")
	)
	(arc
		(start 88.993472 -266.625832)
		(mid 88.866429 -266.761648)
		(end 88.820244 -266.941808)
		(width 0.088646)
		(layer "In2.Cu")
		(net "M_B_CPU1_SA_DQ<16>")
	)
	(segment
		(start 48.277526 -298.462446)
		(end 47.882302 -298.462446)
		(width 0.20066)
		(layer "F.Cu")
		(net "M_B_CPU1_SA_DQ<15>")
	)
	(segment
		(start 93.424248 -270.475456)
		(end 93.424248 -271.011142)
		(width 0.20066)
		(layer "F.Cu")
		(net "M_B_CPU1_SA_DQ<15>")
	)
	(segment
		(start 44.749466 -298.891706)
		(end 44.735242 -298.90593)
		(width 0.101854)
		(layer "F.Cu")
		(net "M_B_CPU1_SA_DQ<15>")
	)
	(segment
		(start 93.424248 -271.011142)
		(end 93.423994 -271.011396)
		(width 0.20066)
		(layer "F.Cu")
		(net "M_B_CPU1_SA_DQ<15>")
	)
	(segment
		(start 44.112942 -298.466764)
		(end 42.415714 -298.466764)
		(width 0.20066)
		(layer "F.Cu")
		(net "M_B_CPU1_SA_DQ<15>")
	)
	(segment
		(start 47.60468 -298.891706)
		(end 47.060358 -298.891706)
		(width 0.20066)
		(layer "F.Cu")
		(net "M_B_CPU1_SA_DQ<15>")
	)
	(segment
		(start 49.143412 -298.466764)
		(end 48.935894 -298.674282)
		(width 0.20066)
		(layer "F.Cu")
		(net "M_B_CPU1_SA_DQ<15>")
	)
	(segment
		(start 44.238926 -298.763436)
		(end 44.238926 -298.592748)
		(width 0.20066)
		(layer "F.Cu")
		(net "M_B_CPU1_SA_DQ<15>")
	)
	(segment
		(start 44.38142 -298.90593)
		(end 44.238926 -298.763436)
		(width 0.20066)
		(layer "F.Cu")
		(net "M_B_CPU1_SA_DQ<15>")
	)
	(segment
		(start 47.882302 -298.462446)
		(end 47.753778 -298.59097)
		(width 0.20066)
		(layer "F.Cu")
		(net "M_B_CPU1_SA_DQ<15>")
	)
	(segment
		(start 44.238926 -298.592748)
		(end 44.112942 -298.466764)
		(width 0.20066)
		(layer "F.Cu")
		(net "M_B_CPU1_SA_DQ<15>")
	)
	(segment
		(start 47.753778 -298.742608)
		(end 47.60468 -298.891706)
		(width 0.20066)
		(layer "F.Cu")
		(net "M_B_CPU1_SA_DQ<15>")
	)
	(segment
		(start 44.987464 -298.891706)
		(end 44.749466 -298.891706)
		(width 0.101854)
		(layer "F.Cu")
		(net "M_B_CPU1_SA_DQ<15>")
	)
	(segment
		(start 48.489362 -298.674282)
		(end 48.277526 -298.462446)
		(width 0.20066)
		(layer "F.Cu")
		(net "M_B_CPU1_SA_DQ<15>")
	)
	(segment
		(start 47.753778 -298.59097)
		(end 47.753778 -298.742608)
		(width 0.20066)
		(layer "F.Cu")
		(net "M_B_CPU1_SA_DQ<15>")
	)
	(segment
		(start 47.060358 -298.891706)
		(end 44.987464 -298.891706)
		(width 0.1016)
		(layer "F.Cu")
		(net "M_B_CPU1_SA_DQ<15>")
	)
	(segment
		(start 49.959514 -298.466764)
		(end 49.143412 -298.466764)
		(width 0.20066)
		(layer "F.Cu")
		(net "M_B_CPU1_SA_DQ<15>")
	)
	(segment
		(start 51.089814 -298.466764)
		(end 49.959514 -298.466764)
		(width 0.20066)
		(layer "F.Cu")
		(net "M_B_CPU1_SA_DQ<15>")
	)
	(segment
		(start 44.735242 -298.90593)
		(end 44.38142 -298.90593)
		(width 0.20066)
		(layer "F.Cu")
		(net "M_B_CPU1_SA_DQ<15>")
	)
	(segment
		(start 48.935894 -298.674282)
		(end 48.489362 -298.674282)
		(width 0.20066)
		(layer "F.Cu")
		(net "M_B_CPU1_SA_DQ<15>")
	)
	(segment
		(start 69.954394 -290.668456)
		(end 69.695822 -290.66871)
		(width 0.18288)
		(layer "In4.Cu")
		(net "M_B_CPU1_SA_DQ<15>")
	)
	(segment
		(start 67.185286 -292.786562)
		(end 67.185286 -293.045134)
		(width 0.18288)
		(layer "In4.Cu")
		(net "M_B_CPU1_SA_DQ<15>")
	)
	(segment
		(start 89.007696 -270.521938)
		(end 89.001854 -270.518636)
		(width 0.088646)
		(layer "In4.Cu")
		(net "M_B_CPU1_SA_DQ<15>")
	)
	(segment
		(start 93.11132 -271.011396)
		(end 93.045788 -270.945864)
		(width 0.088646)
		(layer "In4.Cu")
		(net "M_B_CPU1_SA_DQ<15>")
	)
	(segment
		(start 58.155586 -296.616374)
		(end 56.712866 -298.059094)
		(width 0.18288)
		(layer "In4.Cu")
		(net "M_B_CPU1_SA_DQ<15>")
	)
	(segment
		(start 83.543394 -273.040094)
		(end 83.32724 -273.040094)
		(width 0.18288)
		(layer "In4.Cu")
		(net "M_B_CPU1_SA_DQ<15>")
	)
	(segment
		(start 63.01867 -294.33012)
		(end 62.727586 -294.33012)
		(width 0.18288)
		(layer "In4.Cu")
		(net "M_B_CPU1_SA_DQ<15>")
	)
	(segment
		(start 56.486552 -298.059348)
		(end 55.923942 -298.059348)
		(width 0.18288)
		(layer "In4.Cu")
		(net "M_B_CPU1_SA_DQ<15>")
	)
	(segment
		(start 55.402988 -298.515532)
		(end 55.402988 -298.774358)
		(width 0.18288)
		(layer "In4.Cu")
		(net "M_B_CPU1_SA_DQ<15>")
	)
	(segment
		(start 67.41541 -292.556438)
		(end 67.185286 -292.786562)
		(width 0.18288)
		(layer "In4.Cu")
		(net "M_B_CPU1_SA_DQ<15>")
	)
	(segment
		(start 61.812678 -294.709342)
		(end 60.791344 -295.730676)
		(width 0.18288)
		(layer "In4.Cu")
		(net "M_B_CPU1_SA_DQ<15>")
	)
	(segment
		(start 53.465222 -298.375324)
		(end 53.216048 -298.624498)
		(width 0.18288)
		(layer "In4.Cu")
		(net "M_B_CPU1_SA_DQ<15>")
	)
	(segment
		(start 69.14007 -290.831778)
		(end 69.14007 -291.09035)
		(width 0.18288)
		(layer "In4.Cu")
		(net "M_B_CPU1_SA_DQ<15>")
	)
	(segment
		(start 53.724048 -298.375324)
		(end 53.465222 -298.375324)
		(width 0.18288)
		(layer "In4.Cu")
		(net "M_B_CPU1_SA_DQ<15>")
	)
	(segment
		(start 67.741038 -292.623494)
		(end 67.673982 -292.556438)
		(width 0.18288)
		(layer "In4.Cu")
		(net "M_B_CPU1_SA_DQ<15>")
	)
	(segment
		(start 51.749706 -299.126656)
		(end 51.089814 -298.466764)
		(width 0.18288)
		(layer "In4.Cu")
		(net "M_B_CPU1_SA_DQ<15>")
	)
	(segment
		(start 68.71843 -291.646102)
		(end 68.651374 -291.579046)
		(width 0.18288)
		(layer "In4.Cu")
		(net "M_B_CPU1_SA_DQ<15>")
	)
	(segment
		(start 53.216048 -298.624498)
		(end 53.216048 -298.943776)
		(width 0.18288)
		(layer "In4.Cu")
		(net "M_B_CPU1_SA_DQ<15>")
	)
	(segment
		(start 68.651374 -291.579046)
		(end 68.392802 -291.579046)
		(width 0.18288)
		(layer "In4.Cu")
		(net "M_B_CPU1_SA_DQ<15>")
	)
	(segment
		(start 85.411818 -270.68399)
		(end 85.280246 -270.815816)
		(width 0.088646)
		(layer "In4.Cu")
		(net "M_B_CPU1_SA_DQ<15>")
	)
	(segment
		(start 70.606158 -289.624262)
		(end 70.347586 -289.624262)
		(width 0.18288)
		(layer "In4.Cu")
		(net "M_B_CPU1_SA_DQ<15>")
	)
	(segment
		(start 67.185286 -293.045134)
		(end 67.252342 -293.11219)
		(width 0.18288)
		(layer "In4.Cu")
		(net "M_B_CPU1_SA_DQ<15>")
	)
	(segment
		(start 60.791344 -295.730676)
		(end 59.907932 -295.730676)
		(width 0.18288)
		(layer "In4.Cu")
		(net "M_B_CPU1_SA_DQ<15>")
	)
	(segment
		(start 64.821816 -294.152066)
		(end 63.995554 -294.978328)
		(width 0.18288)
		(layer "In4.Cu")
		(net "M_B_CPU1_SA_DQ<15>")
	)
	(segment
		(start 53.216048 -298.943776)
		(end 53.033168 -299.126656)
		(width 0.18288)
		(layer "In4.Cu")
		(net "M_B_CPU1_SA_DQ<15>")
	)
	(segment
		(start 89.951814 -270.524478)
		(end 89.947496 -270.521938)
		(width 0.088646)
		(layer "In4.Cu")
		(net "M_B_CPU1_SA_DQ<15>")
	)
	(segment
		(start 69.628766 -290.601654)
		(end 69.370194 -290.601654)
		(width 0.18288)
		(layer "In4.Cu")
		(net "M_B_CPU1_SA_DQ<15>")
	)
	(segment
		(start 59.907932 -295.730676)
		(end 59.240928 -296.007028)
		(width 0.18288)
		(layer "In4.Cu")
		(net "M_B_CPU1_SA_DQ<15>")
	)
	(segment
		(start 92.766896 -270.521938)
		(end 92.761054 -270.518636)
		(width 0.088646)
		(layer "In4.Cu")
		(net "M_B_CPU1_SA_DQ<15>")
	)
	(segment
		(start 67.252342 -293.370508)
		(end 66.891916 -293.730934)
		(width 0.18288)
		(layer "In4.Cu")
		(net "M_B_CPU1_SA_DQ<15>")
	)
	(segment
		(start 70.117462 -290.112958)
		(end 70.184518 -290.180014)
		(width 0.18288)
		(layer "In4.Cu")
		(net "M_B_CPU1_SA_DQ<15>")
	)
	(segment
		(start 69.207126 -291.157406)
		(end 69.207126 -291.415724)
		(width 0.18288)
		(layer "In4.Cu")
		(net "M_B_CPU1_SA_DQ<15>")
	)
	(segment
		(start 54.868572 -297.288712)
		(end 54.651656 -297.505628)
		(width 0.18288)
		(layer "In4.Cu")
		(net "M_B_CPU1_SA_DQ<15>")
	)
	(segment
		(start 69.695822 -290.66871)
		(end 69.628766 -290.601654)
		(width 0.18288)
		(layer "In4.Cu")
		(net "M_B_CPU1_SA_DQ<15>")
	)
	(segment
		(start 68.162678 -291.80917)
		(end 68.162678 -292.067742)
		(width 0.18288)
		(layer "In4.Cu")
		(net "M_B_CPU1_SA_DQ<15>")
	)
	(segment
		(start 55.923942 -298.059348)
		(end 55.153306 -297.288712)
		(width 0.18288)
		(layer "In4.Cu")
		(net "M_B_CPU1_SA_DQ<15>")
	)
	(segment
		(start 67.673982 -292.556438)
		(end 67.41541 -292.556438)
		(width 0.18288)
		(layer "In4.Cu")
		(net "M_B_CPU1_SA_DQ<15>")
	)
	(segment
		(start 85.083142 -271.500346)
		(end 83.543394 -273.040094)
		(width 0.18288)
		(layer "In4.Cu")
		(net "M_B_CPU1_SA_DQ<15>")
	)
	(segment
		(start 66.891916 -293.730934)
		(end 65.929002 -293.730934)
		(width 0.18288)
		(layer "In4.Cu")
		(net "M_B_CPU1_SA_DQ<15>")
	)
	(segment
		(start 67.252342 -293.11219)
		(end 67.252342 -293.370508)
		(width 0.18288)
		(layer "In4.Cu")
		(net "M_B_CPU1_SA_DQ<15>")
	)
	(segment
		(start 55.05069 -299.126656)
		(end 54.089808 -299.126656)
		(width 0.18288)
		(layer "In4.Cu")
		(net "M_B_CPU1_SA_DQ<15>")
	)
	(segment
		(start 69.207126 -291.415724)
		(end 68.977002 -291.645848)
		(width 0.18288)
		(layer "In4.Cu")
		(net "M_B_CPU1_SA_DQ<15>")
	)
	(segment
		(start 70.184518 -290.438332)
		(end 69.954394 -290.668456)
		(width 0.18288)
		(layer "In4.Cu")
		(net "M_B_CPU1_SA_DQ<15>")
	)
	(segment
		(start 54.651656 -297.7642)
		(end 55.402988 -298.515532)
		(width 0.18288)
		(layer "In4.Cu")
		(net "M_B_CPU1_SA_DQ<15>")
	)
	(segment
		(start 85.281262 -271.302226)
		(end 85.083142 -271.500346)
		(width 0.088646)
		(layer "In4.Cu")
		(net "M_B_CPU1_SA_DQ<15>")
	)
	(segment
		(start 65.929002 -293.730934)
		(end 65.50787 -294.152066)
		(width 0.18288)
		(layer "In4.Cu")
		(net "M_B_CPU1_SA_DQ<15>")
	)
	(segment
		(start 53.033168 -299.126656)
		(end 51.749706 -299.126656)
		(width 0.18288)
		(layer "In4.Cu")
		(net "M_B_CPU1_SA_DQ<15>")
	)
	(segment
		(start 70.931786 -289.691064)
		(end 70.673214 -289.691318)
		(width 0.18288)
		(layer "In4.Cu")
		(net "M_B_CPU1_SA_DQ<15>")
	)
	(segment
		(start 91.832938 -270.52524)
		(end 91.821254 -270.518636)
		(width 0.088646)
		(layer "In4.Cu")
		(net "M_B_CPU1_SA_DQ<15>")
	)
	(segment
		(start 69.370194 -290.601654)
		(end 69.14007 -290.831778)
		(width 0.18288)
		(layer "In4.Cu")
		(net "M_B_CPU1_SA_DQ<15>")
	)
	(segment
		(start 83.32724 -273.040094)
		(end 74.290682 -282.078176)
		(width 0.18288)
		(layer "In4.Cu")
		(net "M_B_CPU1_SA_DQ<15>")
	)
	(segment
		(start 63.666878 -294.978328)
		(end 63.01867 -294.33012)
		(width 0.18288)
		(layer "In4.Cu")
		(net "M_B_CPU1_SA_DQ<15>")
	)
	(segment
		(start 56.712866 -298.059094)
		(end 56.486552 -298.059348)
		(width 0.18288)
		(layer "In4.Cu")
		(net "M_B_CPU1_SA_DQ<15>")
	)
	(segment
		(start 74.290682 -282.078176)
		(end 71.283068 -289.339782)
		(width 0.18288)
		(layer "In4.Cu")
		(net "M_B_CPU1_SA_DQ<15>")
	)
	(segment
		(start 88.072214 -270.524478)
		(end 88.067896 -270.521938)
		(width 0.088646)
		(layer "In4.Cu")
		(net "M_B_CPU1_SA_DQ<15>")
	)
	(segment
		(start 55.153306 -297.288712)
		(end 54.868572 -297.288712)
		(width 0.18288)
		(layer "In4.Cu")
		(net "M_B_CPU1_SA_DQ<15>")
	)
	(segment
		(start 53.906928 -298.558204)
		(end 53.724048 -298.375324)
		(width 0.18288)
		(layer "In4.Cu")
		(net "M_B_CPU1_SA_DQ<15>")
	)
	(segment
		(start 65.50787 -294.152066)
		(end 64.821816 -294.152066)
		(width 0.18288)
		(layer "In4.Cu")
		(net "M_B_CPU1_SA_DQ<15>")
	)
	(segment
		(start 71.283068 -289.339782)
		(end 70.931786 -289.691064)
		(width 0.18288)
		(layer "In4.Cu")
		(net "M_B_CPU1_SA_DQ<15>")
	)
	(segment
		(start 70.347586 -289.624262)
		(end 70.117462 -289.854386)
		(width 0.18288)
		(layer "In4.Cu")
		(net "M_B_CPU1_SA_DQ<15>")
	)
	(segment
		(start 59.240928 -296.007028)
		(end 58.631582 -296.616374)
		(width 0.18288)
		(layer "In4.Cu")
		(net "M_B_CPU1_SA_DQ<15>")
	)
	(segment
		(start 69.14007 -291.09035)
		(end 69.207126 -291.157406)
		(width 0.18288)
		(layer "In4.Cu")
		(net "M_B_CPU1_SA_DQ<15>")
	)
	(segment
		(start 53.906928 -298.943776)
		(end 53.906928 -298.558204)
		(width 0.18288)
		(layer "In4.Cu")
		(net "M_B_CPU1_SA_DQ<15>")
	)
	(segment
		(start 67.99961 -292.62324)
		(end 67.741038 -292.623494)
		(width 0.18288)
		(layer "In4.Cu")
		(net "M_B_CPU1_SA_DQ<15>")
	)
	(segment
		(start 85.280246 -270.815816)
		(end 85.281262 -271.302226)
		(width 0.088646)
		(layer "In4.Cu")
		(net "M_B_CPU1_SA_DQ<15>")
	)
	(segment
		(start 89.011506 -270.524224)
		(end 89.007696 -270.521938)
		(width 0.088646)
		(layer "In4.Cu")
		(net "M_B_CPU1_SA_DQ<15>")
	)
	(segment
		(start 62.727586 -294.33012)
		(end 61.812678 -294.709342)
		(width 0.18288)
		(layer "In4.Cu")
		(net "M_B_CPU1_SA_DQ<15>")
	)
	(segment
		(start 58.631582 -296.616374)
		(end 58.155586 -296.616374)
		(width 0.18288)
		(layer "In4.Cu")
		(net "M_B_CPU1_SA_DQ<15>")
	)
	(segment
		(start 68.162678 -292.067742)
		(end 68.229734 -292.134798)
		(width 0.18288)
		(layer "In4.Cu")
		(net "M_B_CPU1_SA_DQ<15>")
	)
	(segment
		(start 68.392802 -291.579046)
		(end 68.162678 -291.80917)
		(width 0.18288)
		(layer "In4.Cu")
		(net "M_B_CPU1_SA_DQ<15>")
	)
	(segment
		(start 68.977002 -291.645848)
		(end 68.71843 -291.646102)
		(width 0.18288)
		(layer "In4.Cu")
		(net "M_B_CPU1_SA_DQ<15>")
	)
	(segment
		(start 70.673214 -289.691318)
		(end 70.606158 -289.624262)
		(width 0.18288)
		(layer "In4.Cu")
		(net "M_B_CPU1_SA_DQ<15>")
	)
	(segment
		(start 55.402988 -298.774358)
		(end 55.05069 -299.126656)
		(width 0.18288)
		(layer "In4.Cu")
		(net "M_B_CPU1_SA_DQ<15>")
	)
	(segment
		(start 68.229734 -292.393116)
		(end 67.99961 -292.62324)
		(width 0.18288)
		(layer "In4.Cu")
		(net "M_B_CPU1_SA_DQ<15>")
	)
	(segment
		(start 68.229734 -292.134798)
		(end 68.229734 -292.393116)
		(width 0.18288)
		(layer "In4.Cu")
		(net "M_B_CPU1_SA_DQ<15>")
	)
	(segment
		(start 70.117462 -289.854386)
		(end 70.117462 -290.112958)
		(width 0.18288)
		(layer "In4.Cu")
		(net "M_B_CPU1_SA_DQ<15>")
	)
	(segment
		(start 54.089808 -299.126656)
		(end 53.906928 -298.943776)
		(width 0.18288)
		(layer "In4.Cu")
		(net "M_B_CPU1_SA_DQ<15>")
	)
	(segment
		(start 63.995554 -294.978328)
		(end 63.666878 -294.978328)
		(width 0.18288)
		(layer "In4.Cu")
		(net "M_B_CPU1_SA_DQ<15>")
	)
	(segment
		(start 90.893138 -270.52524)
		(end 90.881454 -270.518636)
		(width 0.088646)
		(layer "In4.Cu")
		(net "M_B_CPU1_SA_DQ<15>")
	)
	(segment
		(start 92.768928 -270.523208)
		(end 92.766896 -270.521938)
		(width 0.088646)
		(layer "In4.Cu")
		(net "M_B_CPU1_SA_DQ<15>")
	)
	(segment
		(start 70.184518 -290.180014)
		(end 70.184518 -290.438332)
		(width 0.18288)
		(layer "In4.Cu")
		(net "M_B_CPU1_SA_DQ<15>")
	)
	(segment
		(start 93.423994 -271.011396)
		(end 93.11132 -271.011396)
		(width 0.088646)
		(layer "In4.Cu")
		(net "M_B_CPU1_SA_DQ<15>")
	)
	(segment
		(start 54.651656 -297.505628)
		(end 54.651656 -297.7642)
		(width 0.18288)
		(layer "In4.Cu")
		(net "M_B_CPU1_SA_DQ<15>")
	)
	(arc
		(start 89.001854 -270.518636)
		(mid 88.721749 -270.446194)
		(end 88.442546 -270.521938)
		(width 0.088646)
		(layer "In4.Cu")
		(net "M_B_CPU1_SA_DQ<15>")
	)
	(arc
		(start 93.045788 -270.945864)
		(mid 92.957192 -270.701902)
		(end 92.768928 -270.523208)
		(width 0.088646)
		(layer "In4.Cu")
		(net "M_B_CPU1_SA_DQ<15>")
	)
	(arc
		(start 86.562692 -270.521938)
		(mid 86.375494 -270.572081)
		(end 86.188296 -270.521938)
		(width 0.088646)
		(layer "In4.Cu")
		(net "M_B_CPU1_SA_DQ<15>")
	)
	(arc
		(start 89.382346 -270.521938)
		(mid 89.197225 -270.572201)
		(end 89.011506 -270.524224)
		(width 0.088646)
		(layer "In4.Cu")
		(net "M_B_CPU1_SA_DQ<15>")
	)
	(arc
		(start 88.067896 -270.521938)
		(mid 87.785194 -270.446162)
		(end 87.502492 -270.521938)
		(width 0.088646)
		(layer "In4.Cu")
		(net "M_B_CPU1_SA_DQ<15>")
	)
	(arc
		(start 91.261946 -270.521938)
		(mid 91.077992 -270.572067)
		(end 90.893138 -270.52524)
		(width 0.088646)
		(layer "In4.Cu")
		(net "M_B_CPU1_SA_DQ<15>")
	)
	(arc
		(start 90.322146 -270.521938)
		(mid 90.137309 -270.572199)
		(end 89.951814 -270.524478)
		(width 0.088646)
		(layer "In4.Cu")
		(net "M_B_CPU1_SA_DQ<15>")
	)
	(arc
		(start 92.201746 -270.521938)
		(mid 92.017792 -270.572067)
		(end 91.832938 -270.52524)
		(width 0.088646)
		(layer "In4.Cu")
		(net "M_B_CPU1_SA_DQ<15>")
	)
	(arc
		(start 89.947496 -270.521938)
		(mid 89.664938 -270.446289)
		(end 89.382346 -270.521938)
		(width 0.088646)
		(layer "In4.Cu")
		(net "M_B_CPU1_SA_DQ<15>")
	)
	(arc
		(start 88.442546 -270.521938)
		(mid 88.257709 -270.572199)
		(end 88.072214 -270.524478)
		(width 0.088646)
		(layer "In4.Cu")
		(net "M_B_CPU1_SA_DQ<15>")
	)
	(arc
		(start 90.881454 -270.518636)
		(mid 90.601349 -270.446194)
		(end 90.322146 -270.521938)
		(width 0.088646)
		(layer "In4.Cu")
		(net "M_B_CPU1_SA_DQ<15>")
	)
	(arc
		(start 87.502492 -270.521938)
		(mid 87.315294 -270.572081)
		(end 87.128096 -270.521938)
		(width 0.088646)
		(layer "In4.Cu")
		(net "M_B_CPU1_SA_DQ<15>")
	)
	(arc
		(start 91.821254 -270.518636)
		(mid 91.541149 -270.446194)
		(end 91.261946 -270.521938)
		(width 0.088646)
		(layer "In4.Cu")
		(net "M_B_CPU1_SA_DQ<15>")
	)
	(arc
		(start 92.761054 -270.518636)
		(mid 92.480949 -270.446194)
		(end 92.201746 -270.521938)
		(width 0.088646)
		(layer "In4.Cu")
		(net "M_B_CPU1_SA_DQ<15>")
	)
	(arc
		(start 85.622892 -270.521938)
		(mid 85.511997 -270.595985)
		(end 85.411818 -270.68399)
		(width 0.088646)
		(layer "In4.Cu")
		(net "M_B_CPU1_SA_DQ<15>")
	)
	(arc
		(start 86.188296 -270.521938)
		(mid 85.905594 -270.446162)
		(end 85.622892 -270.521938)
		(width 0.088646)
		(layer "In4.Cu")
		(net "M_B_CPU1_SA_DQ<15>")
	)
	(arc
		(start 87.128096 -270.521938)
		(mid 86.845394 -270.446162)
		(end 86.562692 -270.521938)
		(width 0.088646)
		(layer "In4.Cu")
		(net "M_B_CPU1_SA_DQ<15>")
	)
	(segment
		(start 48.432974 -300.378622)
		(end 48.004476 -300.378622)
		(width 0.20066)
		(layer "F.Cu")
		(net "M_B_CPU1_SA_DQ<14>")
	)
	(segment
		(start 93.894148 -271.289526)
		(end 93.894148 -271.825212)
		(width 0.20066)
		(layer "F.Cu")
		(net "M_B_CPU1_SA_DQ<14>")
	)
	(segment
		(start 49.959514 -300.166786)
		(end 48.64481 -300.166786)
		(width 0.20066)
		(layer "F.Cu")
		(net "M_B_CPU1_SA_DQ<14>")
	)
	(segment
		(start 47.83709 -299.885608)
		(end 47.693326 -299.741844)
		(width 0.20066)
		(layer "F.Cu")
		(net "M_B_CPU1_SA_DQ<14>")
	)
	(segment
		(start 47.060358 -299.741844)
		(end 45.000418 -299.741844)
		(width 0.1016)
		(layer "F.Cu")
		(net "M_B_CPU1_SA_DQ<14>")
	)
	(segment
		(start 93.893894 -271.289272)
		(end 93.894148 -271.289526)
		(width 0.20066)
		(layer "F.Cu")
		(net "M_B_CPU1_SA_DQ<14>")
	)
	(segment
		(start 48.004476 -300.378622)
		(end 47.83709 -300.211236)
		(width 0.20066)
		(layer "F.Cu")
		(net "M_B_CPU1_SA_DQ<14>")
	)
	(segment
		(start 45.000418 -299.741844)
		(end 44.745402 -299.741844)
		(width 0.101854)
		(layer "F.Cu")
		(net "M_B_CPU1_SA_DQ<14>")
	)
	(segment
		(start 47.83709 -300.211236)
		(end 47.83709 -299.885608)
		(width 0.20066)
		(layer "F.Cu")
		(net "M_B_CPU1_SA_DQ<14>")
	)
	(segment
		(start 44.735242 -299.731684)
		(end 43.99788 -299.731684)
		(width 0.20066)
		(layer "F.Cu")
		(net "M_B_CPU1_SA_DQ<14>")
	)
	(segment
		(start 47.693326 -299.741844)
		(end 47.060358 -299.741844)
		(width 0.20066)
		(layer "F.Cu")
		(net "M_B_CPU1_SA_DQ<14>")
	)
	(segment
		(start 44.745402 -299.741844)
		(end 44.735242 -299.731684)
		(width 0.101854)
		(layer "F.Cu")
		(net "M_B_CPU1_SA_DQ<14>")
	)
	(segment
		(start 48.64481 -300.166786)
		(end 48.432974 -300.378622)
		(width 0.20066)
		(layer "F.Cu")
		(net "M_B_CPU1_SA_DQ<14>")
	)
	(segment
		(start 51.089814 -300.166786)
		(end 49.959514 -300.166786)
		(width 0.20066)
		(layer "F.Cu")
		(net "M_B_CPU1_SA_DQ<14>")
	)
	(segment
		(start 43.562778 -300.166786)
		(end 42.415714 -300.166786)
		(width 0.20066)
		(layer "F.Cu")
		(net "M_B_CPU1_SA_DQ<14>")
	)
	(segment
		(start 43.99788 -299.731684)
		(end 43.562778 -300.166786)
		(width 0.20066)
		(layer "F.Cu")
		(net "M_B_CPU1_SA_DQ<14>")
	)
	(segment
		(start 53.598826 -300.6852)
		(end 53.598826 -300.452028)
		(width 0.18288)
		(layer "In4.Cu")
		(net "M_B_CPU1_SA_DQ<14>")
	)
	(segment
		(start 89.855802 -271.333722)
		(end 89.852246 -271.335754)
		(width 0.088646)
		(layer "In4.Cu")
		(net "M_B_CPU1_SA_DQ<14>")
	)
	(segment
		(start 69.938646 -292.22065)
		(end 69.938646 -292.479222)
		(width 0.18288)
		(layer "In4.Cu")
		(net "M_B_CPU1_SA_DQ<14>")
	)
	(segment
		(start 71.462392 -291.626544)
		(end 70.892162 -292.196774)
		(width 0.18288)
		(layer "In4.Cu")
		(net "M_B_CPU1_SA_DQ<14>")
	)
	(segment
		(start 62.827408 -296.535094)
		(end 62.515242 -296.535094)
		(width 0.18288)
		(layer "In4.Cu")
		(net "M_B_CPU1_SA_DQ<14>")
	)
	(segment
		(start 91.731846 -271.335754)
		(end 91.726004 -271.33931)
		(width 0.088646)
		(layer "In4.Cu")
		(net "M_B_CPU1_SA_DQ<14>")
	)
	(segment
		(start 85.132164 -272.96364)
		(end 84.448142 -273.647662)
		(width 0.088646)
		(layer "In4.Cu")
		(net "M_B_CPU1_SA_DQ<14>")
	)
	(segment
		(start 69.938646 -292.479222)
		(end 70.144894 -292.68547)
		(width 0.18288)
		(layer "In4.Cu")
		(net "M_B_CPU1_SA_DQ<14>")
	)
	(segment
		(start 88.912446 -271.335754)
		(end 88.906604 -271.33931)
		(width 0.088646)
		(layer "In4.Cu")
		(net "M_B_CPU1_SA_DQ<14>")
	)
	(segment
		(start 58.296302 -298.147486)
		(end 56.443372 -300.000416)
		(width 0.18288)
		(layer "In4.Cu")
		(net "M_B_CPU1_SA_DQ<14>")
	)
	(segment
		(start 67.719194 -295.369742)
		(end 65.087246 -295.369742)
		(width 0.18288)
		(layer "In4.Cu")
		(net "M_B_CPU1_SA_DQ<14>")
	)
	(segment
		(start 52.907946 -300.6852)
		(end 52.725066 -300.86808)
		(width 0.18288)
		(layer "In4.Cu")
		(net "M_B_CPU1_SA_DQ<14>")
	)
	(segment
		(start 60.220098 -297.311064)
		(end 59.545728 -297.311064)
		(width 0.18288)
		(layer "In4.Cu")
		(net "M_B_CPU1_SA_DQ<14>")
	)
	(segment
		(start 60.963302 -297.061636)
		(end 60.469526 -297.061636)
		(width 0.18288)
		(layer "In4.Cu")
		(net "M_B_CPU1_SA_DQ<14>")
	)
	(segment
		(start 85.153246 -272.96364)
		(end 85.132164 -272.96364)
		(width 0.088646)
		(layer "In4.Cu")
		(net "M_B_CPU1_SA_DQ<14>")
	)
	(segment
		(start 53.415946 -300.269148)
		(end 53.090826 -300.269148)
		(width 0.18288)
		(layer "In4.Cu")
		(net "M_B_CPU1_SA_DQ<14>")
	)
	(segment
		(start 70.16877 -291.990526)
		(end 69.938646 -292.22065)
		(width 0.18288)
		(layer "In4.Cu")
		(net "M_B_CPU1_SA_DQ<14>")
	)
	(segment
		(start 85.340444 -272.62074)
		(end 85.340444 -272.647918)
		(width 0.088646)
		(layer "In4.Cu")
		(net "M_B_CPU1_SA_DQ<14>")
	)
	(segment
		(start 69.44995 -292.967918)
		(end 69.191378 -292.967918)
		(width 0.18288)
		(layer "In4.Cu")
		(net "M_B_CPU1_SA_DQ<14>")
	)
	(segment
		(start 61.784738 -296.2402)
		(end 60.963302 -297.061636)
		(width 0.18288)
		(layer "In4.Cu")
		(net "M_B_CPU1_SA_DQ<14>")
	)
	(segment
		(start 56.443372 -300.000416)
		(end 55.642256 -300.000416)
		(width 0.18288)
		(layer "In4.Cu")
		(net "M_B_CPU1_SA_DQ<14>")
	)
	(segment
		(start 67.983862 -294.434006)
		(end 68.19011 -294.640254)
		(width 0.18288)
		(layer "In4.Cu")
		(net "M_B_CPU1_SA_DQ<14>")
	)
	(segment
		(start 51.791108 -300.86808)
		(end 51.089814 -300.166786)
		(width 0.18288)
		(layer "In4.Cu")
		(net "M_B_CPU1_SA_DQ<14>")
	)
	(segment
		(start 90.792046 -271.335754)
		(end 90.786204 -271.33931)
		(width 0.088646)
		(layer "In4.Cu")
		(net "M_B_CPU1_SA_DQ<14>")
	)
	(segment
		(start 91.737688 -271.332452)
		(end 91.731846 -271.335754)
		(width 0.088646)
		(layer "In4.Cu")
		(net "M_B_CPU1_SA_DQ<14>")
	)
	(segment
		(start 52.725066 -300.86808)
		(end 51.791108 -300.86808)
		(width 0.18288)
		(layer "In4.Cu")
		(net "M_B_CPU1_SA_DQ<14>")
	)
	(segment
		(start 68.19011 -294.640254)
		(end 68.19011 -294.898826)
		(width 0.18288)
		(layer "In4.Cu")
		(net "M_B_CPU1_SA_DQ<14>")
	)
	(segment
		(start 69.167502 -293.921434)
		(end 68.937378 -294.151558)
		(width 0.18288)
		(layer "In4.Cu")
		(net "M_B_CPU1_SA_DQ<14>")
	)
	(segment
		(start 70.892162 -292.196774)
		(end 70.63359 -292.196774)
		(width 0.18288)
		(layer "In4.Cu")
		(net "M_B_CPU1_SA_DQ<14>")
	)
	(segment
		(start 68.961254 -293.456614)
		(end 69.167502 -293.662862)
		(width 0.18288)
		(layer "In4.Cu")
		(net "M_B_CPU1_SA_DQ<14>")
	)
	(segment
		(start 68.213986 -293.94531)
		(end 67.983862 -294.175434)
		(width 0.18288)
		(layer "In4.Cu")
		(net "M_B_CPU1_SA_DQ<14>")
	)
	(segment
		(start 85.631782 -272.14449)
		(end 85.622892 -272.14957)
		(width 0.088646)
		(layer "In4.Cu")
		(net "M_B_CPU1_SA_DQ<14>")
	)
	(segment
		(start 92.677488 -271.332452)
		(end 92.671646 -271.335754)
		(width 0.088646)
		(layer "In4.Cu")
		(net "M_B_CPU1_SA_DQ<14>")
	)
	(segment
		(start 53.598826 -300.452028)
		(end 53.415946 -300.269148)
		(width 0.18288)
		(layer "In4.Cu")
		(net "M_B_CPU1_SA_DQ<14>")
	)
	(segment
		(start 53.090826 -300.269148)
		(end 52.907946 -300.452028)
		(width 0.18288)
		(layer "In4.Cu")
		(net "M_B_CPU1_SA_DQ<14>")
	)
	(segment
		(start 88.917018 -271.333214)
		(end 88.912446 -271.335754)
		(width 0.088646)
		(layer "In4.Cu")
		(net "M_B_CPU1_SA_DQ<14>")
	)
	(segment
		(start 70.427342 -291.990526)
		(end 70.16877 -291.990526)
		(width 0.18288)
		(layer "In4.Cu")
		(net "M_B_CPU1_SA_DQ<14>")
	)
	(segment
		(start 62.220348 -296.2402)
		(end 61.784738 -296.2402)
		(width 0.18288)
		(layer "In4.Cu")
		(net "M_B_CPU1_SA_DQ<14>")
	)
	(segment
		(start 55.292752 -300.56074)
		(end 54.985412 -300.86808)
		(width 0.18288)
		(layer "In4.Cu")
		(net "M_B_CPU1_SA_DQ<14>")
	)
	(segment
		(start 69.656198 -293.174166)
		(end 69.44995 -292.967918)
		(width 0.18288)
		(layer "In4.Cu")
		(net "M_B_CPU1_SA_DQ<14>")
	)
	(segment
		(start 88.537796 -271.336008)
		(end 88.537796 -271.335754)
		(width 0.088646)
		(layer "In4.Cu")
		(net "M_B_CPU1_SA_DQ<14>")
	)
	(segment
		(start 69.191378 -292.967918)
		(end 68.961254 -293.198042)
		(width 0.18288)
		(layer "In4.Cu")
		(net "M_B_CPU1_SA_DQ<14>")
	)
	(segment
		(start 63.785242 -296.535094)
		(end 63.419482 -296.169334)
		(width 0.18288)
		(layer "In4.Cu")
		(net "M_B_CPU1_SA_DQ<14>")
	)
	(segment
		(start 58.709306 -298.147486)
		(end 58.296302 -298.147486)
		(width 0.18288)
		(layer "In4.Cu")
		(net "M_B_CPU1_SA_DQ<14>")
	)
	(segment
		(start 85.810344 -271.815306)
		(end 85.810344 -271.825212)
		(width 0.088646)
		(layer "In4.Cu")
		(net "M_B_CPU1_SA_DQ<14>")
	)
	(segment
		(start 62.515242 -296.535094)
		(end 62.220348 -296.2402)
		(width 0.18288)
		(layer "In4.Cu")
		(net "M_B_CPU1_SA_DQ<14>")
	)
	(segment
		(start 54.985412 -300.86808)
		(end 53.781706 -300.86808)
		(width 0.18288)
		(layer "In4.Cu")
		(net "M_B_CPU1_SA_DQ<14>")
	)
	(segment
		(start 55.642256 -300.000416)
		(end 55.292752 -300.34992)
		(width 0.18288)
		(layer "In4.Cu")
		(net "M_B_CPU1_SA_DQ<14>")
	)
	(segment
		(start 69.167502 -293.662862)
		(end 69.167502 -293.921434)
		(width 0.18288)
		(layer "In4.Cu")
		(net "M_B_CPU1_SA_DQ<14>")
	)
	(segment
		(start 68.19011 -294.898826)
		(end 67.719194 -295.369742)
		(width 0.18288)
		(layer "In4.Cu")
		(net "M_B_CPU1_SA_DQ<14>")
	)
	(segment
		(start 65.087246 -295.369742)
		(end 64.77127 -295.685718)
		(width 0.18288)
		(layer "In4.Cu")
		(net "M_B_CPU1_SA_DQ<14>")
	)
	(segment
		(start 70.144894 -292.944042)
		(end 69.91477 -293.174166)
		(width 0.18288)
		(layer "In4.Cu")
		(net "M_B_CPU1_SA_DQ<14>")
	)
	(segment
		(start 60.469526 -297.061636)
		(end 60.220098 -297.311064)
		(width 0.18288)
		(layer "In4.Cu")
		(net "M_B_CPU1_SA_DQ<14>")
	)
	(segment
		(start 64.77127 -296.055796)
		(end 64.291972 -296.535094)
		(width 0.18288)
		(layer "In4.Cu")
		(net "M_B_CPU1_SA_DQ<14>")
	)
	(segment
		(start 83.994244 -274.10156)
		(end 83.750658 -274.10156)
		(width 0.18288)
		(layer "In4.Cu")
		(net "M_B_CPU1_SA_DQ<14>")
	)
	(segment
		(start 75.165712 -282.686506)
		(end 71.462392 -291.626544)
		(width 0.18288)
		(layer "In4.Cu")
		(net "M_B_CPU1_SA_DQ<14>")
	)
	(segment
		(start 83.750658 -274.10156)
		(end 75.165712 -282.686506)
		(width 0.18288)
		(layer "In4.Cu")
		(net "M_B_CPU1_SA_DQ<14>")
	)
	(segment
		(start 70.144894 -292.68547)
		(end 70.144894 -292.944042)
		(width 0.18288)
		(layer "In4.Cu")
		(net "M_B_CPU1_SA_DQ<14>")
	)
	(segment
		(start 68.937378 -294.151558)
		(end 68.678806 -294.151558)
		(width 0.18288)
		(layer "In4.Cu")
		(net "M_B_CPU1_SA_DQ<14>")
	)
	(segment
		(start 68.961254 -293.198042)
		(end 68.961254 -293.456614)
		(width 0.18288)
		(layer "In4.Cu")
		(net "M_B_CPU1_SA_DQ<14>")
	)
	(segment
		(start 64.291972 -296.535094)
		(end 63.785242 -296.535094)
		(width 0.18288)
		(layer "In4.Cu")
		(net "M_B_CPU1_SA_DQ<14>")
	)
	(segment
		(start 63.419482 -296.169334)
		(end 63.193168 -296.169334)
		(width 0.18288)
		(layer "In4.Cu")
		(net "M_B_CPU1_SA_DQ<14>")
	)
	(segment
		(start 90.797888 -271.332452)
		(end 90.792046 -271.335754)
		(width 0.088646)
		(layer "In4.Cu")
		(net "M_B_CPU1_SA_DQ<14>")
	)
	(segment
		(start 59.545728 -297.311064)
		(end 58.709306 -298.147486)
		(width 0.18288)
		(layer "In4.Cu")
		(net "M_B_CPU1_SA_DQ<14>")
	)
	(segment
		(start 84.448142 -273.647662)
		(end 83.994244 -274.10156)
		(width 0.18288)
		(layer "In4.Cu")
		(net "M_B_CPU1_SA_DQ<14>")
	)
	(segment
		(start 67.983862 -294.175434)
		(end 67.983862 -294.434006)
		(width 0.18288)
		(layer "In4.Cu")
		(net "M_B_CPU1_SA_DQ<14>")
	)
	(segment
		(start 69.91477 -293.174166)
		(end 69.656198 -293.174166)
		(width 0.18288)
		(layer "In4.Cu")
		(net "M_B_CPU1_SA_DQ<14>")
	)
	(segment
		(start 52.907946 -300.452028)
		(end 52.907946 -300.6852)
		(width 0.18288)
		(layer "In4.Cu")
		(net "M_B_CPU1_SA_DQ<14>")
	)
	(segment
		(start 70.63359 -292.196774)
		(end 70.427342 -291.990526)
		(width 0.18288)
		(layer "In4.Cu")
		(net "M_B_CPU1_SA_DQ<14>")
	)
	(segment
		(start 92.671646 -271.335754)
		(end 92.665804 -271.33931)
		(width 0.088646)
		(layer "In4.Cu")
		(net "M_B_CPU1_SA_DQ<14>")
	)
	(segment
		(start 53.781706 -300.86808)
		(end 53.598826 -300.6852)
		(width 0.18288)
		(layer "In4.Cu")
		(net "M_B_CPU1_SA_DQ<14>")
	)
	(segment
		(start 63.193168 -296.169334)
		(end 62.827408 -296.535094)
		(width 0.18288)
		(layer "In4.Cu")
		(net "M_B_CPU1_SA_DQ<14>")
	)
	(segment
		(start 93.317314 -271.38249)
		(end 93.236796 -271.336008)
		(width 0.088646)
		(layer "In4.Cu")
		(net "M_B_CPU1_SA_DQ<14>")
	)
	(segment
		(start 68.472558 -293.94531)
		(end 68.213986 -293.94531)
		(width 0.18288)
		(layer "In4.Cu")
		(net "M_B_CPU1_SA_DQ<14>")
	)
	(segment
		(start 55.292752 -300.34992)
		(end 55.292752 -300.56074)
		(width 0.18288)
		(layer "In4.Cu")
		(net "M_B_CPU1_SA_DQ<14>")
	)
	(segment
		(start 68.678806 -294.151558)
		(end 68.472558 -293.94531)
		(width 0.18288)
		(layer "In4.Cu")
		(net "M_B_CPU1_SA_DQ<14>")
	)
	(segment
		(start 64.77127 -295.685718)
		(end 64.77127 -296.055796)
		(width 0.18288)
		(layer "In4.Cu")
		(net "M_B_CPU1_SA_DQ<14>")
	)
	(arc
		(start 90.417396 -271.336008)
		(mid 90.136915 -271.260202)
		(end 89.855802 -271.333722)
		(width 0.088646)
		(layer "In4.Cu")
		(net "M_B_CPU1_SA_DQ<14>")
	)
	(arc
		(start 92.665804 -271.33931)
		(mid 92.480949 -271.386228)
		(end 92.296996 -271.336008)
		(width 0.088646)
		(layer "In4.Cu")
		(net "M_B_CPU1_SA_DQ<14>")
	)
	(arc
		(start 90.786204 -271.33931)
		(mid 90.601349 -271.386228)
		(end 90.417396 -271.336008)
		(width 0.088646)
		(layer "In4.Cu")
		(net "M_B_CPU1_SA_DQ<14>")
	)
	(arc
		(start 87.032592 -271.335754)
		(mid 86.845394 -271.385897)
		(end 86.658196 -271.335754)
		(width 0.088646)
		(layer "In4.Cu")
		(net "M_B_CPU1_SA_DQ<14>")
	)
	(arc
		(start 92.296996 -271.336008)
		(mid 92.017822 -271.260209)
		(end 91.737688 -271.332452)
		(width 0.088646)
		(layer "In4.Cu")
		(net "M_B_CPU1_SA_DQ<14>")
	)
	(arc
		(start 89.852246 -271.335754)
		(mid 89.664938 -271.385897)
		(end 89.477596 -271.335754)
		(width 0.088646)
		(layer "In4.Cu")
		(net "M_B_CPU1_SA_DQ<14>")
	)
	(arc
		(start 85.622892 -272.14957)
		(mid 85.420606 -272.348551)
		(end 85.340444 -272.62074)
		(width 0.088646)
		(layer "In4.Cu")
		(net "M_B_CPU1_SA_DQ<14>")
	)
	(arc
		(start 89.477596 -271.335754)
		(mid 89.197652 -271.26011)
		(end 88.917018 -271.333214)
		(width 0.088646)
		(layer "In4.Cu")
		(net "M_B_CPU1_SA_DQ<14>")
	)
	(arc
		(start 91.726004 -271.33931)
		(mid 91.541149 -271.386228)
		(end 91.357196 -271.336008)
		(width 0.088646)
		(layer "In4.Cu")
		(net "M_B_CPU1_SA_DQ<14>")
	)
	(arc
		(start 86.092792 -271.335754)
		(mid 85.888457 -271.538359)
		(end 85.810344 -271.815306)
		(width 0.088646)
		(layer "In4.Cu")
		(net "M_B_CPU1_SA_DQ<14>")
	)
	(arc
		(start 86.658196 -271.335754)
		(mid 86.375494 -271.259978)
		(end 86.092792 -271.335754)
		(width 0.088646)
		(layer "In4.Cu")
		(net "M_B_CPU1_SA_DQ<14>")
	)
	(arc
		(start 88.537796 -271.335754)
		(mid 88.255094 -271.259978)
		(end 87.972392 -271.335754)
		(width 0.088646)
		(layer "In4.Cu")
		(net "M_B_CPU1_SA_DQ<14>")
	)
	(arc
		(start 87.597996 -271.335754)
		(mid 87.315294 -271.259978)
		(end 87.032592 -271.335754)
		(width 0.088646)
		(layer "In4.Cu")
		(net "M_B_CPU1_SA_DQ<14>")
	)
	(arc
		(start 93.894148 -271.825212)
		(mid 93.62019 -271.585013)
		(end 93.317314 -271.38249)
		(width 0.088646)
		(layer "In4.Cu")
		(net "M_B_CPU1_SA_DQ<14>")
	)
	(arc
		(start 88.906604 -271.33931)
		(mid 88.721749 -271.386228)
		(end 88.537796 -271.336008)
		(width 0.088646)
		(layer "In4.Cu")
		(net "M_B_CPU1_SA_DQ<14>")
	)
	(arc
		(start 93.236796 -271.336008)
		(mid 92.957622 -271.260209)
		(end 92.677488 -271.332452)
		(width 0.088646)
		(layer "In4.Cu")
		(net "M_B_CPU1_SA_DQ<14>")
	)
	(arc
		(start 87.972392 -271.335754)
		(mid 87.785194 -271.385897)
		(end 87.597996 -271.335754)
		(width 0.088646)
		(layer "In4.Cu")
		(net "M_B_CPU1_SA_DQ<14>")
	)
	(arc
		(start 85.340444 -272.647918)
		(mid 85.288174 -272.830283)
		(end 85.153246 -272.96364)
		(width 0.088646)
		(layer "In4.Cu")
		(net "M_B_CPU1_SA_DQ<14>")
	)
	(arc
		(start 91.357196 -271.336008)
		(mid 91.078022 -271.260209)
		(end 90.797888 -271.332452)
		(width 0.088646)
		(layer "In4.Cu")
		(net "M_B_CPU1_SA_DQ<14>")
	)
	(arc
		(start 85.810344 -271.825212)
		(mid 85.762665 -272.008112)
		(end 85.631782 -272.14449)
		(width 0.088646)
		(layer "In4.Cu")
		(net "M_B_CPU1_SA_DQ<14>")
	)
	(segment
		(start 44.22013 -299.316648)
		(end 43.795188 -298.891706)
		(width 0.20066)
		(layer "F.Cu")
		(net "M_B_CPU1_SA_DQ<13>")
	)
	(segment
		(start 39.861236 -299.527976)
		(end 39.649908 -299.316648)
		(width 0.20066)
		(layer "F.Cu")
		(net "M_B_CPU1_SA_DQ<13>")
	)
	(segment
		(start 41.29151 -298.882816)
		(end 40.682672 -298.882816)
		(width 0.20066)
		(layer "F.Cu")
		(net "M_B_CPU1_SA_DQ<13>")
	)
	(segment
		(start 40.520112 -299.045376)
		(end 40.520112 -299.373544)
		(width 0.20066)
		(layer "F.Cu")
		(net "M_B_CPU1_SA_DQ<13>")
	)
	(segment
		(start 45.859446 -299.316648)
		(end 44.22013 -299.316648)
		(width 0.20066)
		(layer "F.Cu")
		(net "M_B_CPU1_SA_DQ<13>")
	)
	(segment
		(start 40.36568 -299.527976)
		(end 39.861236 -299.527976)
		(width 0.20066)
		(layer "F.Cu")
		(net "M_B_CPU1_SA_DQ<13>")
	)
	(segment
		(start 39.649908 -299.316648)
		(end 38.315646 -299.316648)
		(width 0.20066)
		(layer "F.Cu")
		(net "M_B_CPU1_SA_DQ<13>")
	)
	(segment
		(start 43.616626 -298.891706)
		(end 43.285918 -298.891706)
		(width 0.101854)
		(layer "F.Cu")
		(net "M_B_CPU1_SA_DQ<13>")
	)
	(segment
		(start 40.520112 -299.373544)
		(end 40.36568 -299.527976)
		(width 0.20066)
		(layer "F.Cu")
		(net "M_B_CPU1_SA_DQ<13>")
	)
	(segment
		(start 40.682672 -298.882816)
		(end 40.520112 -299.045376)
		(width 0.20066)
		(layer "F.Cu")
		(net "M_B_CPU1_SA_DQ<13>")
	)
	(segment
		(start 92.484448 -270.475456)
		(end 92.484448 -271.011142)
		(width 0.20066)
		(layer "F.Cu")
		(net "M_B_CPU1_SA_DQ<13>")
	)
	(segment
		(start 46.964346 -299.316648)
		(end 45.859446 -299.316648)
		(width 0.20066)
		(layer "F.Cu")
		(net "M_B_CPU1_SA_DQ<13>")
	)
	(segment
		(start 43.285918 -298.891706)
		(end 41.3004 -298.891706)
		(width 0.1016)
		(layer "F.Cu")
		(net "M_B_CPU1_SA_DQ<13>")
	)
	(segment
		(start 43.795188 -298.891706)
		(end 43.616626 -298.891706)
		(width 0.20066)
		(layer "F.Cu")
		(net "M_B_CPU1_SA_DQ<13>")
	)
	(segment
		(start 92.484448 -271.011142)
		(end 92.484194 -271.011396)
		(width 0.20066)
		(layer "F.Cu")
		(net "M_B_CPU1_SA_DQ<13>")
	)
	(segment
		(start 41.3004 -298.891706)
		(end 41.29151 -298.882816)
		(width 0.1016)
		(layer "F.Cu")
		(net "M_B_CPU1_SA_DQ<13>")
	)
	(segment
		(start 47.91964 -300.00067)
		(end 47.73676 -299.81779)
		(width 0.18288)
		(layer "In4.Cu")
		(net "M_B_CPU1_SA_DQ<13>")
	)
	(segment
		(start 85.640418 -270.746474)
		(end 85.484208 -270.902684)
		(width 0.088646)
		(layer "In4.Cu")
		(net "M_B_CPU1_SA_DQ<13>")
	)
	(segment
		(start 85.484208 -271.594834)
		(end 84.45754 -272.621502)
		(width 0.088646)
		(layer "In4.Cu")
		(net "M_B_CPU1_SA_DQ<13>")
	)
	(segment
		(start 58.854594 -297.130216)
		(end 58.442098 -297.130216)
		(width 0.18288)
		(layer "In4.Cu")
		(net "M_B_CPU1_SA_DQ<13>")
	)
	(segment
		(start 92.671646 -270.687038)
		(end 92.665804 -270.683736)
		(width 0.088646)
		(layer "In4.Cu")
		(net "M_B_CPU1_SA_DQ<13>")
	)
	(segment
		(start 48.61052 -300.181772)
		(end 48.42764 -300.364652)
		(width 0.18288)
		(layer "In4.Cu")
		(net "M_B_CPU1_SA_DQ<13>")
	)
	(segment
		(start 90.797888 -270.69034)
		(end 90.786204 -270.683736)
		(width 0.088646)
		(layer "In4.Cu")
		(net "M_B_CPU1_SA_DQ<13>")
	)
	(segment
		(start 64.993774 -294.695626)
		(end 64.213232 -295.476168)
		(width 0.18288)
		(layer "In4.Cu")
		(net "M_B_CPU1_SA_DQ<13>")
	)
	(segment
		(start 83.756754 -273.575272)
		(end 83.50377 -273.575272)
		(width 0.18288)
		(layer "In4.Cu")
		(net "M_B_CPU1_SA_DQ<13>")
	)
	(segment
		(start 47.91964 -300.181772)
		(end 47.91964 -300.00067)
		(width 0.18288)
		(layer "In4.Cu")
		(net "M_B_CPU1_SA_DQ<13>")
	)
	(segment
		(start 50.17516 -299.741844)
		(end 49.99228 -299.924724)
		(width 0.18288)
		(layer "In4.Cu")
		(net "M_B_CPU1_SA_DQ<13>")
	)
	(segment
		(start 84.45754 -272.621502)
		(end 84.45754 -272.874486)
		(width 0.088646)
		(layer "In4.Cu")
		(net "M_B_CPU1_SA_DQ<13>")
	)
	(segment
		(start 49.8094 -300.364652)
		(end 49.48428 -300.364652)
		(width 0.18288)
		(layer "In4.Cu")
		(net "M_B_CPU1_SA_DQ<13>")
	)
	(segment
		(start 62.193932 -295.669716)
		(end 61.643006 -295.669716)
		(width 0.18288)
		(layer "In4.Cu")
		(net "M_B_CPU1_SA_DQ<13>")
	)
	(segment
		(start 59.564778 -296.420032)
		(end 58.854594 -297.130216)
		(width 0.18288)
		(layer "In4.Cu")
		(net "M_B_CPU1_SA_DQ<13>")
	)
	(segment
		(start 49.3014 -300.181772)
		(end 49.3014 -299.924724)
		(width 0.18288)
		(layer "In4.Cu")
		(net "M_B_CPU1_SA_DQ<13>")
	)
	(segment
		(start 88.917018 -270.689578)
		(end 88.912446 -270.687038)
		(width 0.088646)
		(layer "In4.Cu")
		(net "M_B_CPU1_SA_DQ<13>")
	)
	(segment
		(start 85.640418 -270.74622)
		(end 85.640418 -270.746474)
		(width 0.088646)
		(layer "In4.Cu")
		(net "M_B_CPU1_SA_DQ<13>")
	)
	(segment
		(start 64.213232 -295.476168)
		(end 62.38748 -295.476168)
		(width 0.18288)
		(layer "In4.Cu")
		(net "M_B_CPU1_SA_DQ<13>")
	)
	(segment
		(start 48.61052 -299.924724)
		(end 48.61052 -300.181772)
		(width 0.18288)
		(layer "In4.Cu")
		(net "M_B_CPU1_SA_DQ<13>")
	)
	(segment
		(start 88.912446 -270.687038)
		(end 88.906604 -270.683736)
		(width 0.088646)
		(layer "In4.Cu")
		(net "M_B_CPU1_SA_DQ<13>")
	)
	(segment
		(start 48.10252 -300.364652)
		(end 47.91964 -300.181772)
		(width 0.18288)
		(layer "In4.Cu")
		(net "M_B_CPU1_SA_DQ<13>")
	)
	(segment
		(start 84.45754 -272.874486)
		(end 84.066126 -273.2659)
		(width 0.088646)
		(layer "In4.Cu")
		(net "M_B_CPU1_SA_DQ<13>")
	)
	(segment
		(start 66.735198 -294.695626)
		(end 64.993774 -294.695626)
		(width 0.18288)
		(layer "In4.Cu")
		(net "M_B_CPU1_SA_DQ<13>")
	)
	(segment
		(start 74.747628 -282.331414)
		(end 71.670418 -289.760406)
		(width 0.18288)
		(layer "In4.Cu")
		(net "M_B_CPU1_SA_DQ<13>")
	)
	(segment
		(start 49.3014 -299.924724)
		(end 49.11852 -299.741844)
		(width 0.18288)
		(layer "In4.Cu")
		(net "M_B_CPU1_SA_DQ<13>")
	)
	(segment
		(start 92.797122 -271.011396)
		(end 92.854526 -270.953992)
		(width 0.088646)
		(layer "In4.Cu")
		(net "M_B_CPU1_SA_DQ<13>")
	)
	(segment
		(start 47.73676 -299.81779)
		(end 47.465488 -299.81779)
		(width 0.18288)
		(layer "In4.Cu")
		(net "M_B_CPU1_SA_DQ<13>")
	)
	(segment
		(start 49.48428 -300.364652)
		(end 49.3014 -300.181772)
		(width 0.18288)
		(layer "In4.Cu")
		(net "M_B_CPU1_SA_DQ<13>")
	)
	(segment
		(start 91.737688 -270.69034)
		(end 91.726004 -270.683736)
		(width 0.088646)
		(layer "In4.Cu")
		(net "M_B_CPU1_SA_DQ<13>")
	)
	(segment
		(start 49.99228 -299.924724)
		(end 49.99228 -300.181772)
		(width 0.18288)
		(layer "In4.Cu")
		(net "M_B_CPU1_SA_DQ<13>")
	)
	(segment
		(start 56.142128 -298.756578)
		(end 55.156862 -299.741844)
		(width 0.18288)
		(layer "In4.Cu")
		(net "M_B_CPU1_SA_DQ<13>")
	)
	(segment
		(start 83.50377 -273.575272)
		(end 74.747628 -282.331414)
		(width 0.18288)
		(layer "In4.Cu")
		(net "M_B_CPU1_SA_DQ<13>")
	)
	(segment
		(start 59.980576 -296.24782)
		(end 59.564778 -296.420032)
		(width 0.18288)
		(layer "In4.Cu")
		(net "M_B_CPU1_SA_DQ<13>")
	)
	(segment
		(start 49.11852 -299.741844)
		(end 48.7934 -299.741844)
		(width 0.18288)
		(layer "In4.Cu")
		(net "M_B_CPU1_SA_DQ<13>")
	)
	(segment
		(start 92.484194 -271.011396)
		(end 92.797122 -271.011396)
		(width 0.088646)
		(layer "In4.Cu")
		(net "M_B_CPU1_SA_DQ<13>")
	)
	(segment
		(start 56.815736 -298.756578)
		(end 56.142128 -298.756578)
		(width 0.18288)
		(layer "In4.Cu")
		(net "M_B_CPU1_SA_DQ<13>")
	)
	(segment
		(start 58.442098 -297.130216)
		(end 56.815736 -298.756578)
		(width 0.18288)
		(layer "In4.Cu")
		(net "M_B_CPU1_SA_DQ<13>")
	)
	(segment
		(start 87.976202 -270.68907)
		(end 87.972392 -270.687038)
		(width 0.088646)
		(layer "In4.Cu")
		(net "M_B_CPU1_SA_DQ<13>")
	)
	(segment
		(start 48.7934 -299.741844)
		(end 48.61052 -299.924724)
		(width 0.18288)
		(layer "In4.Cu")
		(net "M_B_CPU1_SA_DQ<13>")
	)
	(segment
		(start 61.643006 -295.669716)
		(end 61.064902 -296.24782)
		(width 0.18288)
		(layer "In4.Cu")
		(net "M_B_CPU1_SA_DQ<13>")
	)
	(segment
		(start 84.066126 -273.2659)
		(end 83.756754 -273.575272)
		(width 0.18288)
		(layer "In4.Cu")
		(net "M_B_CPU1_SA_DQ<13>")
	)
	(segment
		(start 55.156862 -299.741844)
		(end 50.17516 -299.741844)
		(width 0.18288)
		(layer "In4.Cu")
		(net "M_B_CPU1_SA_DQ<13>")
	)
	(segment
		(start 49.99228 -300.181772)
		(end 49.8094 -300.364652)
		(width 0.18288)
		(layer "In4.Cu")
		(net "M_B_CPU1_SA_DQ<13>")
	)
	(segment
		(start 47.465488 -299.81779)
		(end 46.964346 -299.316648)
		(width 0.18288)
		(layer "In4.Cu")
		(net "M_B_CPU1_SA_DQ<13>")
	)
	(segment
		(start 89.855802 -270.68907)
		(end 89.852246 -270.687038)
		(width 0.088646)
		(layer "In4.Cu")
		(net "M_B_CPU1_SA_DQ<13>")
	)
	(segment
		(start 85.484208 -270.902684)
		(end 85.484208 -271.594834)
		(width 0.088646)
		(layer "In4.Cu")
		(net "M_B_CPU1_SA_DQ<13>")
	)
	(segment
		(start 61.064902 -296.24782)
		(end 59.980576 -296.24782)
		(width 0.18288)
		(layer "In4.Cu")
		(net "M_B_CPU1_SA_DQ<13>")
	)
	(segment
		(start 62.38748 -295.476168)
		(end 62.193932 -295.669716)
		(width 0.18288)
		(layer "In4.Cu")
		(net "M_B_CPU1_SA_DQ<13>")
	)
	(segment
		(start 92.676726 -270.689832)
		(end 92.671646 -270.687038)
		(width 0.088646)
		(layer "In4.Cu")
		(net "M_B_CPU1_SA_DQ<13>")
	)
	(segment
		(start 71.670418 -289.760406)
		(end 66.735198 -294.695626)
		(width 0.18288)
		(layer "In4.Cu")
		(net "M_B_CPU1_SA_DQ<13>")
	)
	(segment
		(start 48.42764 -300.364652)
		(end 48.10252 -300.364652)
		(width 0.18288)
		(layer "In4.Cu")
		(net "M_B_CPU1_SA_DQ<13>")
	)
	(arc
		(start 88.537796 -270.687038)
		(mid 88.257285 -270.762684)
		(end 87.976202 -270.68907)
		(width 0.088646)
		(layer "In4.Cu")
		(net "M_B_CPU1_SA_DQ<13>")
	)
	(arc
		(start 87.597996 -270.687038)
		(mid 87.315294 -270.762814)
		(end 87.032592 -270.687038)
		(width 0.088646)
		(layer "In4.Cu")
		(net "M_B_CPU1_SA_DQ<13>")
	)
	(arc
		(start 87.032592 -270.687038)
		(mid 86.845394 -270.636895)
		(end 86.658196 -270.687038)
		(width 0.088646)
		(layer "In4.Cu")
		(net "M_B_CPU1_SA_DQ<13>")
	)
	(arc
		(start 92.854526 -270.953992)
		(mid 92.795061 -270.802105)
		(end 92.676726 -270.689832)
		(width 0.088646)
		(layer "In4.Cu")
		(net "M_B_CPU1_SA_DQ<13>")
	)
	(arc
		(start 85.718396 -270.687038)
		(mid 85.677466 -270.714071)
		(end 85.640418 -270.74622)
		(width 0.088646)
		(layer "In4.Cu")
		(net "M_B_CPU1_SA_DQ<13>")
	)
	(arc
		(start 87.972392 -270.687038)
		(mid 87.785194 -270.636895)
		(end 87.597996 -270.687038)
		(width 0.088646)
		(layer "In4.Cu")
		(net "M_B_CPU1_SA_DQ<13>")
	)
	(arc
		(start 88.906604 -270.683736)
		(mid 88.721749 -270.636786)
		(end 88.537796 -270.687038)
		(width 0.088646)
		(layer "In4.Cu")
		(net "M_B_CPU1_SA_DQ<13>")
	)
	(arc
		(start 89.477596 -270.687038)
		(mid 89.197652 -270.762682)
		(end 88.917018 -270.689578)
		(width 0.088646)
		(layer "In4.Cu")
		(net "M_B_CPU1_SA_DQ<13>")
	)
	(arc
		(start 89.852246 -270.687038)
		(mid 89.664938 -270.636895)
		(end 89.477596 -270.687038)
		(width 0.088646)
		(layer "In4.Cu")
		(net "M_B_CPU1_SA_DQ<13>")
	)
	(arc
		(start 86.092792 -270.687038)
		(mid 85.905594 -270.636895)
		(end 85.718396 -270.687038)
		(width 0.088646)
		(layer "In4.Cu")
		(net "M_B_CPU1_SA_DQ<13>")
	)
	(arc
		(start 90.417396 -270.687038)
		(mid 90.136885 -270.762684)
		(end 89.855802 -270.68907)
		(width 0.088646)
		(layer "In4.Cu")
		(net "M_B_CPU1_SA_DQ<13>")
	)
	(arc
		(start 92.665804 -270.683736)
		(mid 92.480949 -270.636786)
		(end 92.296996 -270.687038)
		(width 0.088646)
		(layer "In4.Cu")
		(net "M_B_CPU1_SA_DQ<13>")
	)
	(arc
		(start 86.658196 -270.687038)
		(mid 86.375494 -270.762814)
		(end 86.092792 -270.687038)
		(width 0.088646)
		(layer "In4.Cu")
		(net "M_B_CPU1_SA_DQ<13>")
	)
	(arc
		(start 90.786204 -270.683736)
		(mid 90.601349 -270.636786)
		(end 90.417396 -270.687038)
		(width 0.088646)
		(layer "In4.Cu")
		(net "M_B_CPU1_SA_DQ<13>")
	)
	(arc
		(start 91.726004 -270.683736)
		(mid 91.541149 -270.636786)
		(end 91.357196 -270.687038)
		(width 0.088646)
		(layer "In4.Cu")
		(net "M_B_CPU1_SA_DQ<13>")
	)
	(arc
		(start 92.296996 -270.687038)
		(mid 92.017793 -270.762678)
		(end 91.737688 -270.69034)
		(width 0.088646)
		(layer "In4.Cu")
		(net "M_B_CPU1_SA_DQ<13>")
	)
	(arc
		(start 91.357196 -270.687038)
		(mid 91.077993 -270.762678)
		(end 90.797888 -270.69034)
		(width 0.088646)
		(layer "In4.Cu")
		(net "M_B_CPU1_SA_DQ<13>")
	)
	(segment
		(start 46.964346 -301.01667)
		(end 45.859446 -301.01667)
		(width 0.20066)
		(layer "F.Cu")
		(net "M_B_CPU1_SA_DQ<12>")
	)
	(segment
		(start 92.014548 -271.289526)
		(end 92.014548 -271.825212)
		(width 0.20066)
		(layer "F.Cu")
		(net "M_B_CPU1_SA_DQ<12>")
	)
	(segment
		(start 40.520112 -301.08271)
		(end 40.347392 -301.25543)
		(width 0.20066)
		(layer "F.Cu")
		(net "M_B_CPU1_SA_DQ<12>")
	)
	(segment
		(start 41.29151 -300.5836)
		(end 40.729662 -300.5836)
		(width 0.20066)
		(layer "F.Cu")
		(net "M_B_CPU1_SA_DQ<12>")
	)
	(segment
		(start 41.547542 -300.591728)
		(end 41.299638 -300.591728)
		(width 0.101854)
		(layer "F.Cu")
		(net "M_B_CPU1_SA_DQ<12>")
	)
	(segment
		(start 41.299638 -300.591728)
		(end 41.29151 -300.5836)
		(width 0.101854)
		(layer "F.Cu")
		(net "M_B_CPU1_SA_DQ<12>")
	)
	(segment
		(start 44.490386 -301.01667)
		(end 44.065444 -300.591728)
		(width 0.20066)
		(layer "F.Cu")
		(net "M_B_CPU1_SA_DQ<12>")
	)
	(segment
		(start 92.014294 -271.289272)
		(end 92.014548 -271.289526)
		(width 0.20066)
		(layer "F.Cu")
		(net "M_B_CPU1_SA_DQ<12>")
	)
	(segment
		(start 40.347392 -301.25543)
		(end 39.888668 -301.25543)
		(width 0.20066)
		(layer "F.Cu")
		(net "M_B_CPU1_SA_DQ<12>")
	)
	(segment
		(start 43.616626 -300.591728)
		(end 41.547542 -300.591728)
		(width 0.1016)
		(layer "F.Cu")
		(net "M_B_CPU1_SA_DQ<12>")
	)
	(segment
		(start 40.520112 -300.79315)
		(end 40.520112 -301.08271)
		(width 0.20066)
		(layer "F.Cu")
		(net "M_B_CPU1_SA_DQ<12>")
	)
	(segment
		(start 45.859446 -301.01667)
		(end 44.490386 -301.01667)
		(width 0.20066)
		(layer "F.Cu")
		(net "M_B_CPU1_SA_DQ<12>")
	)
	(segment
		(start 44.065444 -300.591728)
		(end 43.616626 -300.591728)
		(width 0.20066)
		(layer "F.Cu")
		(net "M_B_CPU1_SA_DQ<12>")
	)
	(segment
		(start 39.649908 -301.01667)
		(end 38.315646 -301.01667)
		(width 0.20066)
		(layer "F.Cu")
		(net "M_B_CPU1_SA_DQ<12>")
	)
	(segment
		(start 40.729662 -300.5836)
		(end 40.520112 -300.79315)
		(width 0.20066)
		(layer "F.Cu")
		(net "M_B_CPU1_SA_DQ<12>")
	)
	(segment
		(start 39.888668 -301.25543)
		(end 39.649908 -301.01667)
		(width 0.20066)
		(layer "F.Cu")
		(net "M_B_CPU1_SA_DQ<12>")
	)
	(segment
		(start 62.666372 -297.69308)
		(end 62.224412 -297.25112)
		(width 0.18288)
		(layer "In4.Cu")
		(net "M_B_CPU1_SA_DQ<12>")
	)
	(segment
		(start 50.343562 -301.852584)
		(end 50.160682 -302.035464)
		(width 0.18288)
		(layer "In4.Cu")
		(net "M_B_CPU1_SA_DQ<12>")
	)
	(segment
		(start 92.014548 -271.825212)
		(end 92.014294 -271.824958)
		(width 0.088646)
		(layer "In4.Cu")
		(net "M_B_CPU1_SA_DQ<12>")
	)
	(segment
		(start 86.000844 -271.825212)
		(end 86.000844 -271.843754)
		(width 0.088646)
		(layer "In4.Cu")
		(net "M_B_CPU1_SA_DQ<12>")
	)
	(segment
		(start 48.446182 -302.035464)
		(end 48.263302 -301.852584)
		(width 0.18288)
		(layer "In4.Cu")
		(net "M_B_CPU1_SA_DQ<12>")
	)
	(segment
		(start 48.263302 -301.624746)
		(end 48.080422 -301.441866)
		(width 0.18288)
		(layer "In4.Cu")
		(net "M_B_CPU1_SA_DQ<12>")
	)
	(segment
		(start 48.956722 -301.852584)
		(end 48.773842 -302.035464)
		(width 0.18288)
		(layer "In4.Cu")
		(net "M_B_CPU1_SA_DQ<12>")
	)
	(segment
		(start 50.343562 -301.624746)
		(end 50.343562 -301.852584)
		(width 0.18288)
		(layer "In4.Cu")
		(net "M_B_CPU1_SA_DQ<12>")
	)
	(segment
		(start 48.956722 -301.624746)
		(end 48.956722 -301.852584)
		(width 0.18288)
		(layer "In4.Cu")
		(net "M_B_CPU1_SA_DQ<12>")
	)
	(segment
		(start 56.765444 -300.534324)
		(end 56.191404 -300.534324)
		(width 0.18288)
		(layer "In4.Cu")
		(net "M_B_CPU1_SA_DQ<12>")
	)
	(segment
		(start 59.796934 -297.875198)
		(end 58.950606 -298.721526)
		(width 0.18288)
		(layer "In4.Cu")
		(net "M_B_CPU1_SA_DQ<12>")
	)
	(segment
		(start 50.160682 -302.035464)
		(end 49.833022 -302.035464)
		(width 0.18288)
		(layer "In4.Cu")
		(net "M_B_CPU1_SA_DQ<12>")
	)
	(segment
		(start 53.721762 -301.441866)
		(end 53.427376 -301.736252)
		(width 0.18288)
		(layer "In4.Cu")
		(net "M_B_CPU1_SA_DQ<12>")
	)
	(segment
		(start 60.47232 -297.875198)
		(end 59.796934 -297.875198)
		(width 0.18288)
		(layer "In4.Cu")
		(net "M_B_CPU1_SA_DQ<12>")
	)
	(segment
		(start 50.526442 -301.441866)
		(end 50.343562 -301.624746)
		(width 0.18288)
		(layer "In4.Cu")
		(net "M_B_CPU1_SA_DQ<12>")
	)
	(segment
		(start 49.833022 -302.035464)
		(end 49.650142 -301.852584)
		(width 0.18288)
		(layer "In4.Cu")
		(net "M_B_CPU1_SA_DQ<12>")
	)
	(segment
		(start 48.263302 -301.852584)
		(end 48.263302 -301.624746)
		(width 0.18288)
		(layer "In4.Cu")
		(net "M_B_CPU1_SA_DQ<12>")
	)
	(segment
		(start 64.557148 -297.06824)
		(end 63.75654 -297.06824)
		(width 0.18288)
		(layer "In4.Cu")
		(net "M_B_CPU1_SA_DQ<12>")
	)
	(segment
		(start 90.887296 -271.500854)
		(end 90.881454 -271.50441)
		(width 0.088646)
		(layer "In4.Cu")
		(net "M_B_CPU1_SA_DQ<12>")
	)
	(segment
		(start 89.011506 -271.498822)
		(end 89.007696 -271.500854)
		(width 0.088646)
		(layer "In4.Cu")
		(net "M_B_CPU1_SA_DQ<12>")
	)
	(segment
		(start 71.83628 -292.06444)
		(end 67.539362 -296.361358)
		(width 0.18288)
		(layer "In4.Cu")
		(net "M_B_CPU1_SA_DQ<12>")
	)
	(segment
		(start 75.59929 -282.979876)
		(end 71.83628 -292.06444)
		(width 0.18288)
		(layer "In4.Cu")
		(net "M_B_CPU1_SA_DQ<12>")
	)
	(segment
		(start 89.007696 -271.500854)
		(end 89.001854 -271.50441)
		(width 0.088646)
		(layer "In4.Cu")
		(net "M_B_CPU1_SA_DQ<12>")
	)
	(segment
		(start 65.26403 -296.361358)
		(end 64.557148 -297.06824)
		(width 0.18288)
		(layer "In4.Cu")
		(net "M_B_CPU1_SA_DQ<12>")
	)
	(segment
		(start 55.283862 -301.441866)
		(end 53.721762 -301.441866)
		(width 0.18288)
		(layer "In4.Cu")
		(net "M_B_CPU1_SA_DQ<12>")
	)
	(segment
		(start 47.389542 -301.441866)
		(end 46.964346 -301.01667)
		(width 0.18288)
		(layer "In4.Cu")
		(net "M_B_CPU1_SA_DQ<12>")
	)
	(segment
		(start 90.893138 -271.497552)
		(end 90.887296 -271.500854)
		(width 0.088646)
		(layer "In4.Cu")
		(net "M_B_CPU1_SA_DQ<12>")
	)
	(segment
		(start 49.467262 -301.441866)
		(end 49.139602 -301.441866)
		(width 0.18288)
		(layer "In4.Cu")
		(net "M_B_CPU1_SA_DQ<12>")
	)
	(segment
		(start 91.659202 -271.729962)
		(end 91.261946 -271.500854)
		(width 0.088646)
		(layer "In4.Cu")
		(net "M_B_CPU1_SA_DQ<12>")
	)
	(segment
		(start 49.650142 -301.624746)
		(end 49.467262 -301.441866)
		(width 0.18288)
		(layer "In4.Cu")
		(net "M_B_CPU1_SA_DQ<12>")
	)
	(segment
		(start 48.080422 -301.441866)
		(end 47.389542 -301.441866)
		(width 0.18288)
		(layer "In4.Cu")
		(net "M_B_CPU1_SA_DQ<12>")
	)
	(segment
		(start 85.531198 -272.630646)
		(end 85.531198 -272.649188)
		(width 0.088646)
		(layer "In4.Cu")
		(net "M_B_CPU1_SA_DQ<12>")
	)
	(segment
		(start 88.442546 -271.500854)
		(end 88.442292 -271.500854)
		(width 0.088646)
		(layer "In4.Cu")
		(net "M_B_CPU1_SA_DQ<12>")
	)
	(segment
		(start 60.780422 -297.567096)
		(end 60.47232 -297.875198)
		(width 0.18288)
		(layer "In4.Cu")
		(net "M_B_CPU1_SA_DQ<12>")
	)
	(segment
		(start 49.650142 -301.852584)
		(end 49.650142 -301.624746)
		(width 0.18288)
		(layer "In4.Cu")
		(net "M_B_CPU1_SA_DQ<12>")
	)
	(segment
		(start 56.191404 -300.534324)
		(end 55.283862 -301.441866)
		(width 0.18288)
		(layer "In4.Cu")
		(net "M_B_CPU1_SA_DQ<12>")
	)
	(segment
		(start 48.773842 -302.035464)
		(end 48.446182 -302.035464)
		(width 0.18288)
		(layer "In4.Cu")
		(net "M_B_CPU1_SA_DQ<12>")
	)
	(segment
		(start 63.75654 -297.06824)
		(end 63.1317 -297.69308)
		(width 0.18288)
		(layer "In4.Cu")
		(net "M_B_CPU1_SA_DQ<12>")
	)
	(segment
		(start 89.951814 -271.498314)
		(end 89.947496 -271.500854)
		(width 0.088646)
		(layer "In4.Cu")
		(net "M_B_CPU1_SA_DQ<12>")
	)
	(segment
		(start 83.801204 -274.777962)
		(end 75.59929 -282.979876)
		(width 0.18288)
		(layer "In4.Cu")
		(net "M_B_CPU1_SA_DQ<12>")
	)
	(segment
		(start 85.360764 -273.050508)
		(end 84.966302 -273.44497)
		(width 0.088646)
		(layer "In4.Cu")
		(net "M_B_CPU1_SA_DQ<12>")
	)
	(segment
		(start 84.966302 -273.612864)
		(end 83.801204 -274.777962)
		(width 0.088646)
		(layer "In4.Cu")
		(net "M_B_CPU1_SA_DQ<12>")
	)
	(segment
		(start 52.736496 -301.441866)
		(end 50.526442 -301.441866)
		(width 0.18288)
		(layer "In4.Cu")
		(net "M_B_CPU1_SA_DQ<12>")
	)
	(segment
		(start 61.55055 -297.567096)
		(end 60.780422 -297.567096)
		(width 0.18288)
		(layer "In4.Cu")
		(net "M_B_CPU1_SA_DQ<12>")
	)
	(segment
		(start 63.1317 -297.69308)
		(end 62.666372 -297.69308)
		(width 0.18288)
		(layer "In4.Cu")
		(net "M_B_CPU1_SA_DQ<12>")
	)
	(segment
		(start 53.030882 -301.736252)
		(end 52.736496 -301.441866)
		(width 0.18288)
		(layer "In4.Cu")
		(net "M_B_CPU1_SA_DQ<12>")
	)
	(segment
		(start 67.539362 -296.361358)
		(end 65.26403 -296.361358)
		(width 0.18288)
		(layer "In4.Cu")
		(net "M_B_CPU1_SA_DQ<12>")
	)
	(segment
		(start 86.188296 -271.500854)
		(end 86.179406 -271.505934)
		(width 0.088646)
		(layer "In4.Cu")
		(net "M_B_CPU1_SA_DQ<12>")
	)
	(segment
		(start 84.966302 -273.44497)
		(end 84.966302 -273.612864)
		(width 0.088646)
		(layer "In4.Cu")
		(net "M_B_CPU1_SA_DQ<12>")
	)
	(segment
		(start 61.866526 -297.25112)
		(end 61.55055 -297.567096)
		(width 0.18288)
		(layer "In4.Cu")
		(net "M_B_CPU1_SA_DQ<12>")
	)
	(segment
		(start 53.427376 -301.736252)
		(end 53.030882 -301.736252)
		(width 0.18288)
		(layer "In4.Cu")
		(net "M_B_CPU1_SA_DQ<12>")
	)
	(segment
		(start 62.224412 -297.25112)
		(end 61.866526 -297.25112)
		(width 0.18288)
		(layer "In4.Cu")
		(net "M_B_CPU1_SA_DQ<12>")
	)
	(segment
		(start 49.139602 -301.441866)
		(end 48.956722 -301.624746)
		(width 0.18288)
		(layer "In4.Cu")
		(net "M_B_CPU1_SA_DQ<12>")
	)
	(segment
		(start 58.950606 -298.721526)
		(end 58.578242 -298.721526)
		(width 0.18288)
		(layer "In4.Cu")
		(net "M_B_CPU1_SA_DQ<12>")
	)
	(segment
		(start 58.578242 -298.721526)
		(end 56.765444 -300.534324)
		(width 0.18288)
		(layer "In4.Cu")
		(net "M_B_CPU1_SA_DQ<12>")
	)
	(arc
		(start 86.562692 -271.500854)
		(mid 86.375494 -271.450711)
		(end 86.188296 -271.500854)
		(width 0.088646)
		(layer "In4.Cu")
		(net "M_B_CPU1_SA_DQ<12>")
	)
	(arc
		(start 89.947496 -271.500854)
		(mid 89.664938 -271.576503)
		(end 89.382346 -271.500854)
		(width 0.088646)
		(layer "In4.Cu")
		(net "M_B_CPU1_SA_DQ<12>")
	)
	(arc
		(start 90.881454 -271.50441)
		(mid 90.601319 -271.576693)
		(end 90.322146 -271.500854)
		(width 0.088646)
		(layer "In4.Cu")
		(net "M_B_CPU1_SA_DQ<12>")
	)
	(arc
		(start 87.502492 -271.500854)
		(mid 87.315294 -271.450711)
		(end 87.128096 -271.500854)
		(width 0.088646)
		(layer "In4.Cu")
		(net "M_B_CPU1_SA_DQ<12>")
	)
	(arc
		(start 89.382346 -271.500854)
		(mid 89.197196 -271.450716)
		(end 89.011506 -271.498822)
		(width 0.088646)
		(layer "In4.Cu")
		(net "M_B_CPU1_SA_DQ<12>")
	)
	(arc
		(start 86.000844 -271.843754)
		(mid 85.920682 -272.115943)
		(end 85.718396 -272.314924)
		(width 0.088646)
		(layer "In4.Cu")
		(net "M_B_CPU1_SA_DQ<12>")
	)
	(arc
		(start 88.067896 -271.500854)
		(mid 87.785194 -271.57663)
		(end 87.502492 -271.500854)
		(width 0.088646)
		(layer "In4.Cu")
		(net "M_B_CPU1_SA_DQ<12>")
	)
	(arc
		(start 85.718396 -272.314924)
		(mid 85.583463 -272.448278)
		(end 85.531198 -272.630646)
		(width 0.088646)
		(layer "In4.Cu")
		(net "M_B_CPU1_SA_DQ<12>")
	)
	(arc
		(start 90.322146 -271.500854)
		(mid 90.137309 -271.450593)
		(end 89.951814 -271.498314)
		(width 0.088646)
		(layer "In4.Cu")
		(net "M_B_CPU1_SA_DQ<12>")
	)
	(arc
		(start 85.531198 -272.649188)
		(mid 85.48502 -272.866436)
		(end 85.360764 -273.050508)
		(width 0.088646)
		(layer "In4.Cu")
		(net "M_B_CPU1_SA_DQ<12>")
	)
	(arc
		(start 89.001854 -271.50441)
		(mid 88.721719 -271.576693)
		(end 88.442546 -271.500854)
		(width 0.088646)
		(layer "In4.Cu")
		(net "M_B_CPU1_SA_DQ<12>")
	)
	(arc
		(start 87.128096 -271.500854)
		(mid 86.845394 -271.57663)
		(end 86.562692 -271.500854)
		(width 0.088646)
		(layer "In4.Cu")
		(net "M_B_CPU1_SA_DQ<12>")
	)
	(arc
		(start 86.179406 -271.505934)
		(mid 86.048492 -271.642294)
		(end 86.000844 -271.825212)
		(width 0.088646)
		(layer "In4.Cu")
		(net "M_B_CPU1_SA_DQ<12>")
	)
	(arc
		(start 88.442292 -271.500854)
		(mid 88.255094 -271.450711)
		(end 88.067896 -271.500854)
		(width 0.088646)
		(layer "In4.Cu")
		(net "M_B_CPU1_SA_DQ<12>")
	)
	(arc
		(start 92.014294 -271.824958)
		(mid 91.830487 -271.800846)
		(end 91.659202 -271.729962)
		(width 0.088646)
		(layer "In4.Cu")
		(net "M_B_CPU1_SA_DQ<12>")
	)
	(arc
		(start 91.261946 -271.500854)
		(mid 91.077992 -271.450725)
		(end 90.893138 -271.497552)
		(width 0.088646)
		(layer "In4.Cu")
		(net "M_B_CPU1_SA_DQ<12>")
	)
	(segment
		(start 44.38142 -304.85588)
		(end 44.238926 -304.713386)
		(width 0.20066)
		(layer "F.Cu")
		(net "M_B_CPU1_SA_DQ<11>")
	)
	(segment
		(start 44.112942 -304.416714)
		(end 42.415714 -304.416714)
		(width 0.20066)
		(layer "F.Cu")
		(net "M_B_CPU1_SA_DQ<11>")
	)
	(segment
		(start 49.143412 -304.416714)
		(end 48.935894 -304.624232)
		(width 0.20066)
		(layer "F.Cu")
		(net "M_B_CPU1_SA_DQ<11>")
	)
	(segment
		(start 47.753778 -304.54092)
		(end 47.753778 -304.692558)
		(width 0.20066)
		(layer "F.Cu")
		(net "M_B_CPU1_SA_DQ<11>")
	)
	(segment
		(start 48.489362 -304.624232)
		(end 48.277526 -304.412396)
		(width 0.20066)
		(layer "F.Cu")
		(net "M_B_CPU1_SA_DQ<11>")
	)
	(segment
		(start 44.735242 -304.85588)
		(end 44.38142 -304.85588)
		(width 0.20066)
		(layer "F.Cu")
		(net "M_B_CPU1_SA_DQ<11>")
	)
	(segment
		(start 47.753778 -304.692558)
		(end 47.60468 -304.841656)
		(width 0.20066)
		(layer "F.Cu")
		(net "M_B_CPU1_SA_DQ<11>")
	)
	(segment
		(start 44.749466 -304.841656)
		(end 44.735242 -304.85588)
		(width 0.101854)
		(layer "F.Cu")
		(net "M_B_CPU1_SA_DQ<11>")
	)
	(segment
		(start 47.060358 -304.841656)
		(end 44.987464 -304.841656)
		(width 0.1016)
		(layer "F.Cu")
		(net "M_B_CPU1_SA_DQ<11>")
	)
	(segment
		(start 44.987464 -304.841656)
		(end 44.749466 -304.841656)
		(width 0.101854)
		(layer "F.Cu")
		(net "M_B_CPU1_SA_DQ<11>")
	)
	(segment
		(start 49.959514 -304.416714)
		(end 49.143412 -304.416714)
		(width 0.20066)
		(layer "F.Cu")
		(net "M_B_CPU1_SA_DQ<11>")
	)
	(segment
		(start 51.089814 -304.416714)
		(end 49.959514 -304.416714)
		(width 0.20066)
		(layer "F.Cu")
		(net "M_B_CPU1_SA_DQ<11>")
	)
	(segment
		(start 48.935894 -304.624232)
		(end 48.489362 -304.624232)
		(width 0.20066)
		(layer "F.Cu")
		(net "M_B_CPU1_SA_DQ<11>")
	)
	(segment
		(start 44.238926 -304.713386)
		(end 44.238926 -304.542698)
		(width 0.20066)
		(layer "F.Cu")
		(net "M_B_CPU1_SA_DQ<11>")
	)
	(segment
		(start 44.238926 -304.542698)
		(end 44.112942 -304.416714)
		(width 0.20066)
		(layer "F.Cu")
		(net "M_B_CPU1_SA_DQ<11>")
	)
	(segment
		(start 47.882302 -304.412396)
		(end 47.753778 -304.54092)
		(width 0.20066)
		(layer "F.Cu")
		(net "M_B_CPU1_SA_DQ<11>")
	)
	(segment
		(start 48.277526 -304.412396)
		(end 47.882302 -304.412396)
		(width 0.20066)
		(layer "F.Cu")
		(net "M_B_CPU1_SA_DQ<11>")
	)
	(segment
		(start 47.60468 -304.841656)
		(end 47.060358 -304.841656)
		(width 0.20066)
		(layer "F.Cu")
		(net "M_B_CPU1_SA_DQ<11>")
	)
	(arc
		(start 93.893894 -272.917158)
		(mid 93.893957 -273.185128)
		(end 93.894148 -273.453098)
		(width 0.20066)
		(layer "F.Cu")
		(net "M_B_CPU1_SA_DQ<11>")
	)
	(segment
		(start 53.561742 -304.346864)
		(end 53.213762 -304.346864)
		(width 0.18288)
		(layer "In4.Cu")
		(net "M_B_CPU1_SA_DQ<11>")
	)
	(segment
		(start 59.978036 -302.888396)
		(end 59.751976 -302.888396)
		(width 0.18288)
		(layer "In4.Cu")
		(net "M_B_CPU1_SA_DQ<11>")
	)
	(segment
		(start 59.191144 -302.586136)
		(end 58.944764 -302.832516)
		(width 0.18288)
		(layer "In4.Cu")
		(net "M_B_CPU1_SA_DQ<11>")
	)
	(segment
		(start 52.870862 -304.955194)
		(end 51.628294 -304.955194)
		(width 0.18288)
		(layer "In4.Cu")
		(net "M_B_CPU1_SA_DQ<11>")
	)
	(segment
		(start 91.270836 -273.772376)
		(end 91.261946 -273.777456)
		(width 0.088646)
		(layer "In4.Cu")
		(net "M_B_CPU1_SA_DQ<11>")
	)
	(segment
		(start 60.631578 -302.135286)
		(end 60.631578 -302.234854)
		(width 0.18288)
		(layer "In4.Cu")
		(net "M_B_CPU1_SA_DQ<11>")
	)
	(segment
		(start 87.041482 -274.586192)
		(end 87.032592 -274.591272)
		(width 0.088646)
		(layer "In4.Cu")
		(net "M_B_CPU1_SA_DQ<11>")
	)
	(segment
		(start 62.91453 -301.52975)
		(end 62.738762 -301.705518)
		(width 0.18288)
		(layer "In4.Cu")
		(net "M_B_CPU1_SA_DQ<11>")
	)
	(segment
		(start 54.971188 -304.955194)
		(end 53.881782 -304.955194)
		(width 0.18288)
		(layer "In4.Cu")
		(net "M_B_CPU1_SA_DQ<11>")
	)
	(segment
		(start 59.751976 -302.888396)
		(end 59.449716 -302.586136)
		(width 0.18288)
		(layer "In4.Cu")
		(net "M_B_CPU1_SA_DQ<11>")
	)
	(segment
		(start 61.32576 -301.68596)
		(end 61.14288 -301.50308)
		(width 0.18288)
		(layer "In4.Cu")
		(net "M_B_CPU1_SA_DQ<11>")
	)
	(segment
		(start 56.925972 -304.03927)
		(end 55.887112 -304.03927)
		(width 0.18288)
		(layer "In4.Cu")
		(net "M_B_CPU1_SA_DQ<11>")
	)
	(segment
		(start 53.030882 -304.795174)
		(end 52.870862 -304.955194)
		(width 0.18288)
		(layer "In4.Cu")
		(net "M_B_CPU1_SA_DQ<11>")
	)
	(segment
		(start 93.538548 -273.357848)
		(end 93.141546 -273.12874)
		(width 0.088646)
		(layer "In4.Cu")
		(net "M_B_CPU1_SA_DQ<11>")
	)
	(segment
		(start 83.894422 -278.718772)
		(end 77.427074 -285.18612)
		(width 0.18288)
		(layer "In4.Cu")
		(net "M_B_CPU1_SA_DQ<11>")
	)
	(segment
		(start 91.832938 -273.125438)
		(end 91.738704 -273.178778)
		(width 0.088646)
		(layer "In4.Cu")
		(net "M_B_CPU1_SA_DQ<11>")
	)
	(segment
		(start 53.881782 -304.955194)
		(end 53.721762 -304.795174)
		(width 0.18288)
		(layer "In4.Cu")
		(net "M_B_CPU1_SA_DQ<11>")
	)
	(segment
		(start 86.101428 -276.214078)
		(end 86.092538 -276.219158)
		(width 0.088646)
		(layer "In4.Cu")
		(net "M_B_CPU1_SA_DQ<11>")
	)
	(segment
		(start 61.32576 -302.131984)
		(end 61.32576 -301.68596)
		(width 0.18288)
		(layer "In4.Cu")
		(net "M_B_CPU1_SA_DQ<11>")
	)
	(segment
		(start 60.631578 -302.234854)
		(end 59.978036 -302.888396)
		(width 0.18288)
		(layer "In4.Cu")
		(net "M_B_CPU1_SA_DQ<11>")
	)
	(segment
		(start 65.09258 -300.591728)
		(end 64.154558 -301.52975)
		(width 0.18288)
		(layer "In4.Cu")
		(net "M_B_CPU1_SA_DQ<11>")
	)
	(segment
		(start 58.944764 -303.058576)
		(end 59.26328 -303.377092)
		(width 0.18288)
		(layer "In4.Cu")
		(net "M_B_CPU1_SA_DQ<11>")
	)
	(segment
		(start 53.721762 -304.506884)
		(end 53.561742 -304.346864)
		(width 0.18288)
		(layer "In4.Cu")
		(net "M_B_CPU1_SA_DQ<11>")
	)
	(segment
		(start 61.14288 -301.50308)
		(end 60.7949 -301.50308)
		(width 0.18288)
		(layer "In4.Cu")
		(net "M_B_CPU1_SA_DQ<11>")
	)
	(segment
		(start 85.631782 -277.027894)
		(end 85.622892 -277.032974)
		(width 0.088646)
		(layer "In4.Cu")
		(net "M_B_CPU1_SA_DQ<11>")
	)
	(segment
		(start 59.26328 -303.603152)
		(end 58.827162 -304.03927)
		(width 0.18288)
		(layer "In4.Cu")
		(net "M_B_CPU1_SA_DQ<11>")
	)
	(segment
		(start 58.827162 -304.03927)
		(end 57.818782 -304.03927)
		(width 0.18288)
		(layer "In4.Cu")
		(net "M_B_CPU1_SA_DQ<11>")
	)
	(segment
		(start 53.213762 -304.346864)
		(end 53.030882 -304.529744)
		(width 0.18288)
		(layer "In4.Cu")
		(net "M_B_CPU1_SA_DQ<11>")
	)
	(segment
		(start 92.772738 -273.125438)
		(end 92.761054 -273.132042)
		(width 0.088646)
		(layer "In4.Cu")
		(net "M_B_CPU1_SA_DQ<11>")
	)
	(segment
		(start 60.7949 -301.50308)
		(end 60.63488 -301.6631)
		(width 0.18288)
		(layer "In4.Cu")
		(net "M_B_CPU1_SA_DQ<11>")
	)
	(segment
		(start 57.818782 -304.03927)
		(end 57.593992 -303.81448)
		(width 0.18288)
		(layer "In4.Cu")
		(net "M_B_CPU1_SA_DQ<11>")
	)
	(segment
		(start 91.738704 -273.178778)
		(end 91.43619 -273.552158)
		(width 0.088646)
		(layer "In4.Cu")
		(net "M_B_CPU1_SA_DQ<11>")
	)
	(segment
		(start 62.586616 -302.292004)
		(end 61.48578 -302.292004)
		(width 0.18288)
		(layer "In4.Cu")
		(net "M_B_CPU1_SA_DQ<11>")
	)
	(segment
		(start 86.27999 -275.876258)
		(end 86.27999 -275.8948)
		(width 0.088646)
		(layer "In4.Cu")
		(net "M_B_CPU1_SA_DQ<11>")
	)
	(segment
		(start 51.628294 -304.955194)
		(end 51.089814 -304.416714)
		(width 0.18288)
		(layer "In4.Cu")
		(net "M_B_CPU1_SA_DQ<11>")
	)
	(segment
		(start 85.810344 -276.693122)
		(end 85.810344 -276.708616)
		(width 0.088646)
		(layer "In4.Cu")
		(net "M_B_CPU1_SA_DQ<11>")
	)
	(segment
		(start 55.887112 -304.03927)
		(end 54.971188 -304.955194)
		(width 0.18288)
		(layer "In4.Cu")
		(net "M_B_CPU1_SA_DQ<11>")
	)
	(segment
		(start 61.48578 -302.292004)
		(end 61.32576 -302.131984)
		(width 0.18288)
		(layer "In4.Cu")
		(net "M_B_CPU1_SA_DQ<11>")
	)
	(segment
		(start 85.493352 -277.119842)
		(end 83.894422 -278.718772)
		(width 0.088646)
		(layer "In4.Cu")
		(net "M_B_CPU1_SA_DQ<11>")
	)
	(segment
		(start 77.427074 -285.18612)
		(end 74.042016 -293.357808)
		(width 0.18288)
		(layer "In4.Cu")
		(net "M_B_CPU1_SA_DQ<11>")
	)
	(segment
		(start 59.26328 -303.377092)
		(end 59.26328 -303.603152)
		(width 0.18288)
		(layer "In4.Cu")
		(net "M_B_CPU1_SA_DQ<11>")
	)
	(segment
		(start 66.80835 -300.591474)
		(end 65.926208 -300.591474)
		(width 0.18288)
		(layer "In4.Cu")
		(net "M_B_CPU1_SA_DQ<11>")
	)
	(segment
		(start 64.154558 -301.52975)
		(end 62.91453 -301.52975)
		(width 0.18288)
		(layer "In4.Cu")
		(net "M_B_CPU1_SA_DQ<11>")
	)
	(segment
		(start 57.593992 -303.81448)
		(end 57.150762 -303.81448)
		(width 0.18288)
		(layer "In4.Cu")
		(net "M_B_CPU1_SA_DQ<11>")
	)
	(segment
		(start 90.332306 -273.77136)
		(end 90.321892 -273.777456)
		(width 0.088646)
		(layer "In4.Cu")
		(net "M_B_CPU1_SA_DQ<11>")
	)
	(segment
		(start 60.63488 -302.131984)
		(end 60.631578 -302.135286)
		(width 0.18288)
		(layer "In4.Cu")
		(net "M_B_CPU1_SA_DQ<11>")
	)
	(segment
		(start 60.63488 -301.6631)
		(end 60.63488 -302.131984)
		(width 0.18288)
		(layer "In4.Cu")
		(net "M_B_CPU1_SA_DQ<11>")
	)
	(segment
		(start 58.944764 -302.832516)
		(end 58.944764 -303.058576)
		(width 0.18288)
		(layer "In4.Cu")
		(net "M_B_CPU1_SA_DQ<11>")
	)
	(segment
		(start 53.721762 -304.795174)
		(end 53.721762 -304.506884)
		(width 0.18288)
		(layer "In4.Cu")
		(net "M_B_CPU1_SA_DQ<11>")
	)
	(segment
		(start 65.925954 -300.591728)
		(end 65.09258 -300.591728)
		(width 0.18288)
		(layer "In4.Cu")
		(net "M_B_CPU1_SA_DQ<11>")
	)
	(segment
		(start 62.738762 -301.705518)
		(end 62.738762 -302.139858)
		(width 0.18288)
		(layer "In4.Cu")
		(net "M_B_CPU1_SA_DQ<11>")
	)
	(segment
		(start 87.220044 -274.257008)
		(end 87.220044 -274.266914)
		(width 0.088646)
		(layer "In4.Cu")
		(net "M_B_CPU1_SA_DQ<11>")
	)
	(segment
		(start 65.926208 -300.591474)
		(end 65.925954 -300.591728)
		(width 0.18288)
		(layer "In4.Cu")
		(net "M_B_CPU1_SA_DQ<11>")
	)
	(segment
		(start 62.738762 -302.139858)
		(end 62.586616 -302.292004)
		(width 0.18288)
		(layer "In4.Cu")
		(net "M_B_CPU1_SA_DQ<11>")
	)
	(segment
		(start 59.449716 -302.586136)
		(end 59.191144 -302.586136)
		(width 0.18288)
		(layer "In4.Cu")
		(net "M_B_CPU1_SA_DQ<11>")
	)
	(segment
		(start 57.150762 -303.81448)
		(end 56.925972 -304.03927)
		(width 0.18288)
		(layer "In4.Cu")
		(net "M_B_CPU1_SA_DQ<11>")
	)
	(segment
		(start 74.042016 -293.357808)
		(end 66.80835 -300.591474)
		(width 0.18288)
		(layer "In4.Cu")
		(net "M_B_CPU1_SA_DQ<11>")
	)
	(segment
		(start 87.032592 -274.591272)
		(end 87.026496 -274.594828)
		(width 0.088646)
		(layer "In4.Cu")
		(net "M_B_CPU1_SA_DQ<11>")
	)
	(segment
		(start 53.030882 -304.529744)
		(end 53.030882 -304.795174)
		(width 0.18288)
		(layer "In4.Cu")
		(net "M_B_CPU1_SA_DQ<11>")
	)
	(segment
		(start 86.571328 -275.400008)
		(end 86.562438 -275.405088)
		(width 0.088646)
		(layer "In4.Cu")
		(net "M_B_CPU1_SA_DQ<11>")
	)
	(arc
		(start 89.382092 -273.777456)
		(mid 89.194894 -273.827599)
		(end 89.007696 -273.777456)
		(width 0.088646)
		(layer "In4.Cu")
		(net "M_B_CPU1_SA_DQ<11>")
	)
	(arc
		(start 85.810344 -276.708616)
		(mid 85.762665 -276.891516)
		(end 85.631782 -277.027894)
		(width 0.088646)
		(layer "In4.Cu")
		(net "M_B_CPU1_SA_DQ<11>")
	)
	(arc
		(start 85.596984 -277.04669)
		(mid 85.542051 -277.078849)
		(end 85.493352 -277.119842)
		(width 0.088646)
		(layer "In4.Cu")
		(net "M_B_CPU1_SA_DQ<11>")
	)
	(arc
		(start 91.261946 -273.777456)
		(mid 91.074748 -273.827599)
		(end 90.88755 -273.777456)
		(width 0.088646)
		(layer "In4.Cu")
		(net "M_B_CPU1_SA_DQ<11>")
	)
	(arc
		(start 87.220044 -274.266914)
		(mid 87.172365 -274.449814)
		(end 87.041482 -274.586192)
		(width 0.088646)
		(layer "In4.Cu")
		(net "M_B_CPU1_SA_DQ<11>")
	)
	(arc
		(start 87.502492 -273.777456)
		(mid 87.298157 -273.980061)
		(end 87.220044 -274.257008)
		(width 0.088646)
		(layer "In4.Cu")
		(net "M_B_CPU1_SA_DQ<11>")
	)
	(arc
		(start 87.026496 -274.594828)
		(mid 86.823909 -274.801179)
		(end 86.74989 -275.08073)
		(width 0.088646)
		(layer "In4.Cu")
		(net "M_B_CPU1_SA_DQ<11>")
	)
	(arc
		(start 91.43619 -273.552158)
		(mid 91.374505 -273.67804)
		(end 91.270836 -273.772376)
		(width 0.088646)
		(layer "In4.Cu")
		(net "M_B_CPU1_SA_DQ<11>")
	)
	(arc
		(start 90.88755 -273.777456)
		(mid 90.610737 -273.701586)
		(end 90.332306 -273.77136)
		(width 0.088646)
		(layer "In4.Cu")
		(net "M_B_CPU1_SA_DQ<11>")
	)
	(arc
		(start 86.092538 -276.219158)
		(mid 85.889715 -276.419389)
		(end 85.810344 -276.693122)
		(width 0.088646)
		(layer "In4.Cu")
		(net "M_B_CPU1_SA_DQ<11>")
	)
	(arc
		(start 88.442292 -273.777456)
		(mid 88.255094 -273.827599)
		(end 88.067896 -273.777456)
		(width 0.088646)
		(layer "In4.Cu")
		(net "M_B_CPU1_SA_DQ<11>")
	)
	(arc
		(start 89.007696 -273.777456)
		(mid 88.724994 -273.70168)
		(end 88.442292 -273.777456)
		(width 0.088646)
		(layer "In4.Cu")
		(net "M_B_CPU1_SA_DQ<11>")
	)
	(arc
		(start 85.622892 -277.032974)
		(mid 85.610071 -277.040083)
		(end 85.596984 -277.04669)
		(width 0.088646)
		(layer "In4.Cu")
		(net "M_B_CPU1_SA_DQ<11>")
	)
	(arc
		(start 86.27999 -275.8948)
		(mid 86.232311 -276.0777)
		(end 86.101428 -276.214078)
		(width 0.088646)
		(layer "In4.Cu")
		(net "M_B_CPU1_SA_DQ<11>")
	)
	(arc
		(start 92.201746 -273.12874)
		(mid 92.017792 -273.078611)
		(end 91.832938 -273.125438)
		(width 0.088646)
		(layer "In4.Cu")
		(net "M_B_CPU1_SA_DQ<11>")
	)
	(arc
		(start 93.894148 -273.453098)
		(mid 93.710079 -273.428874)
		(end 93.538548 -273.357848)
		(width 0.088646)
		(layer "In4.Cu")
		(net "M_B_CPU1_SA_DQ<11>")
	)
	(arc
		(start 86.562438 -275.405088)
		(mid 86.360152 -275.604069)
		(end 86.27999 -275.876258)
		(width 0.088646)
		(layer "In4.Cu")
		(net "M_B_CPU1_SA_DQ<11>")
	)
	(arc
		(start 92.761054 -273.132042)
		(mid 92.480949 -273.204484)
		(end 92.201746 -273.12874)
		(width 0.088646)
		(layer "In4.Cu")
		(net "M_B_CPU1_SA_DQ<11>")
	)
	(arc
		(start 89.947496 -273.777456)
		(mid 89.664794 -273.70168)
		(end 89.382092 -273.777456)
		(width 0.088646)
		(layer "In4.Cu")
		(net "M_B_CPU1_SA_DQ<11>")
	)
	(arc
		(start 88.067896 -273.777456)
		(mid 87.785194 -273.70168)
		(end 87.502492 -273.777456)
		(width 0.088646)
		(layer "In4.Cu")
		(net "M_B_CPU1_SA_DQ<11>")
	)
	(arc
		(start 90.321892 -273.777456)
		(mid 90.134694 -273.827599)
		(end 89.947496 -273.777456)
		(width 0.088646)
		(layer "In4.Cu")
		(net "M_B_CPU1_SA_DQ<11>")
	)
	(arc
		(start 86.74989 -275.08073)
		(mid 86.702211 -275.26363)
		(end 86.571328 -275.400008)
		(width 0.088646)
		(layer "In4.Cu")
		(net "M_B_CPU1_SA_DQ<11>")
	)
	(arc
		(start 93.141546 -273.12874)
		(mid 92.957592 -273.078611)
		(end 92.772738 -273.125438)
		(width 0.088646)
		(layer "In4.Cu")
		(net "M_B_CPU1_SA_DQ<11>")
	)
	(segment
		(start 48.432974 -306.328572)
		(end 48.004476 -306.328572)
		(width 0.20066)
		(layer "F.Cu")
		(net "M_B_CPU1_SA_DQ<10>")
	)
	(segment
		(start 47.83709 -305.835558)
		(end 47.693326 -305.691794)
		(width 0.20066)
		(layer "F.Cu")
		(net "M_B_CPU1_SA_DQ<10>")
	)
	(segment
		(start 44.745402 -305.691794)
		(end 44.735242 -305.681634)
		(width 0.101854)
		(layer "F.Cu")
		(net "M_B_CPU1_SA_DQ<10>")
	)
	(segment
		(start 45.000418 -305.691794)
		(end 44.745402 -305.691794)
		(width 0.101854)
		(layer "F.Cu")
		(net "M_B_CPU1_SA_DQ<10>")
	)
	(segment
		(start 93.424248 -273.730974)
		(end 93.424248 -274.26666)
		(width 0.20066)
		(layer "F.Cu")
		(net "M_B_CPU1_SA_DQ<10>")
	)
	(segment
		(start 43.99788 -305.681634)
		(end 43.562778 -306.116736)
		(width 0.20066)
		(layer "F.Cu")
		(net "M_B_CPU1_SA_DQ<10>")
	)
	(segment
		(start 51.089814 -306.116736)
		(end 49.959514 -306.116736)
		(width 0.20066)
		(layer "F.Cu")
		(net "M_B_CPU1_SA_DQ<10>")
	)
	(segment
		(start 93.424248 -274.26666)
		(end 93.423994 -274.266914)
		(width 0.20066)
		(layer "F.Cu")
		(net "M_B_CPU1_SA_DQ<10>")
	)
	(segment
		(start 47.83709 -306.161186)
		(end 47.83709 -305.835558)
		(width 0.20066)
		(layer "F.Cu")
		(net "M_B_CPU1_SA_DQ<10>")
	)
	(segment
		(start 44.735242 -305.681634)
		(end 43.99788 -305.681634)
		(width 0.20066)
		(layer "F.Cu")
		(net "M_B_CPU1_SA_DQ<10>")
	)
	(segment
		(start 48.64481 -306.116736)
		(end 48.432974 -306.328572)
		(width 0.20066)
		(layer "F.Cu")
		(net "M_B_CPU1_SA_DQ<10>")
	)
	(segment
		(start 47.060358 -305.691794)
		(end 45.000418 -305.691794)
		(width 0.1016)
		(layer "F.Cu")
		(net "M_B_CPU1_SA_DQ<10>")
	)
	(segment
		(start 43.562778 -306.116736)
		(end 42.415714 -306.116736)
		(width 0.20066)
		(layer "F.Cu")
		(net "M_B_CPU1_SA_DQ<10>")
	)
	(segment
		(start 47.693326 -305.691794)
		(end 47.060358 -305.691794)
		(width 0.20066)
		(layer "F.Cu")
		(net "M_B_CPU1_SA_DQ<10>")
	)
	(segment
		(start 49.959514 -306.116736)
		(end 48.64481 -306.116736)
		(width 0.20066)
		(layer "F.Cu")
		(net "M_B_CPU1_SA_DQ<10>")
	)
	(segment
		(start 48.004476 -306.328572)
		(end 47.83709 -306.161186)
		(width 0.20066)
		(layer "F.Cu")
		(net "M_B_CPU1_SA_DQ<10>")
	)
	(segment
		(start 54.80177 -306.770278)
		(end 53.947822 -306.770278)
		(width 0.18288)
		(layer "In4.Cu")
		(net "M_B_CPU1_SA_DQ<10>")
	)
	(segment
		(start 78.255368 -285.80334)
		(end 74.773028 -294.210994)
		(width 0.18288)
		(layer "In4.Cu")
		(net "M_B_CPU1_SA_DQ<10>")
	)
	(segment
		(start 63.21298 -304.17008)
		(end 62.54115 -304.84191)
		(width 0.18288)
		(layer "In4.Cu")
		(net "M_B_CPU1_SA_DQ<10>")
	)
	(segment
		(start 55.725822 -305.846226)
		(end 54.80177 -306.770278)
		(width 0.18288)
		(layer "In4.Cu")
		(net "M_B_CPU1_SA_DQ<10>")
	)
	(segment
		(start 53.775102 -306.597558)
		(end 53.775102 -306.38242)
		(width 0.18288)
		(layer "In4.Cu")
		(net "M_B_CPU1_SA_DQ<10>")
	)
	(segment
		(start 57.648348 -305.155092)
		(end 57.300368 -305.155092)
		(width 0.18288)
		(layer "In4.Cu")
		(net "M_B_CPU1_SA_DQ<10>")
	)
	(segment
		(start 86.750144 -276.693122)
		(end 86.750144 -276.708616)
		(width 0.088646)
		(layer "In4.Cu")
		(net "M_B_CPU1_SA_DQ<10>")
	)
	(segment
		(start 66.810636 -302.173386)
		(end 66.810636 -302.872648)
		(width 0.18288)
		(layer "In4.Cu")
		(net "M_B_CPU1_SA_DQ<10>")
	)
	(segment
		(start 91.921076 -274.191222)
		(end 91.919044 -274.27555)
		(width 0.088646)
		(layer "In4.Cu")
		(net "M_B_CPU1_SA_DQ<10>")
	)
	(segment
		(start 87.972392 -274.591272)
		(end 87.9602 -274.598384)
		(width 0.088646)
		(layer "In4.Cu")
		(net "M_B_CPU1_SA_DQ<10>")
	)
	(segment
		(start 59.708542 -304.84191)
		(end 58.704226 -305.846226)
		(width 0.18288)
		(layer "In4.Cu")
		(net "M_B_CPU1_SA_DQ<10>")
	)
	(segment
		(start 62.54115 -304.84191)
		(end 59.708542 -304.84191)
		(width 0.18288)
		(layer "In4.Cu")
		(net "M_B_CPU1_SA_DQ<10>")
	)
	(segment
		(start 51.566572 -306.116736)
		(end 51.089814 -306.116736)
		(width 0.18288)
		(layer "In4.Cu")
		(net "M_B_CPU1_SA_DQ<10>")
	)
	(segment
		(start 53.084222 -306.35956)
		(end 53.084222 -306.601876)
		(width 0.18288)
		(layer "In4.Cu")
		(net "M_B_CPU1_SA_DQ<10>")
	)
	(segment
		(start 66.810636 -302.872648)
		(end 66.541904 -303.14138)
		(width 0.18288)
		(layer "In4.Cu")
		(net "M_B_CPU1_SA_DQ<10>")
	)
	(segment
		(start 86.571582 -277.027894)
		(end 86.562692 -277.032974)
		(width 0.088646)
		(layer "In4.Cu")
		(net "M_B_CPU1_SA_DQ<10>")
	)
	(segment
		(start 57.140348 -305.686206)
		(end 56.980328 -305.846226)
		(width 0.18288)
		(layer "In4.Cu")
		(net "M_B_CPU1_SA_DQ<10>")
	)
	(segment
		(start 53.244242 -306.19954)
		(end 53.084222 -306.35956)
		(width 0.18288)
		(layer "In4.Cu")
		(net "M_B_CPU1_SA_DQ<10>")
	)
	(segment
		(start 87.21979 -275.876258)
		(end 87.21979 -275.8948)
		(width 0.088646)
		(layer "In4.Cu")
		(net "M_B_CPU1_SA_DQ<10>")
	)
	(segment
		(start 53.947822 -306.770278)
		(end 53.775102 -306.597558)
		(width 0.18288)
		(layer "In4.Cu")
		(net "M_B_CPU1_SA_DQ<10>")
	)
	(segment
		(start 84.78266 -278.5745)
		(end 84.78266 -279.276048)
		(width 0.088646)
		(layer "In4.Cu")
		(net "M_B_CPU1_SA_DQ<10>")
	)
	(segment
		(start 58.704226 -305.846226)
		(end 57.991248 -305.846226)
		(width 0.18288)
		(layer "In4.Cu")
		(net "M_B_CPU1_SA_DQ<10>")
	)
	(segment
		(start 52.924202 -306.761896)
		(end 52.211732 -306.761896)
		(width 0.18288)
		(layer "In4.Cu")
		(net "M_B_CPU1_SA_DQ<10>")
	)
	(segment
		(start 63.21298 -303.10328)
		(end 63.21298 -304.17008)
		(width 0.18288)
		(layer "In4.Cu")
		(net "M_B_CPU1_SA_DQ<10>")
	)
	(segment
		(start 87.511128 -275.400008)
		(end 87.502238 -275.405088)
		(width 0.088646)
		(layer "In4.Cu")
		(net "M_B_CPU1_SA_DQ<10>")
	)
	(segment
		(start 64.330072 -303.14138)
		(end 64.156844 -302.968152)
		(width 0.18288)
		(layer "In4.Cu")
		(net "M_B_CPU1_SA_DQ<10>")
	)
	(segment
		(start 52.211732 -306.761896)
		(end 51.566572 -306.116736)
		(width 0.18288)
		(layer "In4.Cu")
		(net "M_B_CPU1_SA_DQ<10>")
	)
	(segment
		(start 53.084222 -306.601876)
		(end 52.924202 -306.761896)
		(width 0.18288)
		(layer "In4.Cu")
		(net "M_B_CPU1_SA_DQ<10>")
	)
	(segment
		(start 91.35745 -274.591272)
		(end 91.347036 -274.585176)
		(width 0.088646)
		(layer "In4.Cu")
		(net "M_B_CPU1_SA_DQ<10>")
	)
	(segment
		(start 57.300368 -305.155092)
		(end 57.140348 -305.315112)
		(width 0.18288)
		(layer "In4.Cu")
		(net "M_B_CPU1_SA_DQ<10>")
	)
	(segment
		(start 66.541904 -303.14138)
		(end 64.330072 -303.14138)
		(width 0.18288)
		(layer "In4.Cu")
		(net "M_B_CPU1_SA_DQ<10>")
	)
	(segment
		(start 57.991248 -305.846226)
		(end 57.831228 -305.686206)
		(width 0.18288)
		(layer "In4.Cu")
		(net "M_B_CPU1_SA_DQ<10>")
	)
	(segment
		(start 92.766896 -273.777456)
		(end 92.761054 -273.774154)
		(width 0.088646)
		(layer "In4.Cu")
		(net "M_B_CPU1_SA_DQ<10>")
	)
	(segment
		(start 57.831228 -305.686206)
		(end 57.831228 -305.337972)
		(width 0.18288)
		(layer "In4.Cu")
		(net "M_B_CPU1_SA_DQ<10>")
	)
	(segment
		(start 64.156844 -302.7299)
		(end 63.996824 -302.56988)
		(width 0.18288)
		(layer "In4.Cu")
		(net "M_B_CPU1_SA_DQ<10>")
	)
	(segment
		(start 57.140348 -305.315112)
		(end 57.140348 -305.686206)
		(width 0.18288)
		(layer "In4.Cu")
		(net "M_B_CPU1_SA_DQ<10>")
	)
	(segment
		(start 74.773028 -294.210994)
		(end 66.810636 -302.173386)
		(width 0.18288)
		(layer "In4.Cu")
		(net "M_B_CPU1_SA_DQ<10>")
	)
	(segment
		(start 63.996824 -302.56988)
		(end 63.74638 -302.56988)
		(width 0.18288)
		(layer "In4.Cu")
		(net "M_B_CPU1_SA_DQ<10>")
	)
	(segment
		(start 92.866972 -273.836384)
		(end 92.766896 -273.777456)
		(width 0.088646)
		(layer "In4.Cu")
		(net "M_B_CPU1_SA_DQ<10>")
	)
	(segment
		(start 56.980328 -305.846226)
		(end 55.725822 -305.846226)
		(width 0.18288)
		(layer "In4.Cu")
		(net "M_B_CPU1_SA_DQ<10>")
	)
	(segment
		(start 92.871036 -273.83867)
		(end 92.869512 -273.837908)
		(width 0.088646)
		(layer "In4.Cu")
		(net "M_B_CPU1_SA_DQ<10>")
	)
	(segment
		(start 84.617306 -279.441402)
		(end 78.255368 -285.80334)
		(width 0.18288)
		(layer "In4.Cu")
		(net "M_B_CPU1_SA_DQ<10>")
	)
	(segment
		(start 86.27999 -277.508462)
		(end 86.27999 -277.522686)
		(width 0.088646)
		(layer "In4.Cu")
		(net "M_B_CPU1_SA_DQ<10>")
	)
	(segment
		(start 84.78266 -279.276048)
		(end 84.617306 -279.441402)
		(width 0.088646)
		(layer "In4.Cu")
		(net "M_B_CPU1_SA_DQ<10>")
	)
	(segment
		(start 63.74638 -302.56988)
		(end 63.21298 -303.10328)
		(width 0.18288)
		(layer "In4.Cu")
		(net "M_B_CPU1_SA_DQ<10>")
	)
	(segment
		(start 87.041228 -276.214078)
		(end 87.032338 -276.219158)
		(width 0.088646)
		(layer "In4.Cu")
		(net "M_B_CPU1_SA_DQ<10>")
	)
	(segment
		(start 53.592222 -306.19954)
		(end 53.244242 -306.19954)
		(width 0.18288)
		(layer "In4.Cu")
		(net "M_B_CPU1_SA_DQ<10>")
	)
	(segment
		(start 85.459316 -277.897844)
		(end 84.78266 -278.5745)
		(width 0.088646)
		(layer "In4.Cu")
		(net "M_B_CPU1_SA_DQ<10>")
	)
	(segment
		(start 53.775102 -306.38242)
		(end 53.592222 -306.19954)
		(width 0.18288)
		(layer "In4.Cu")
		(net "M_B_CPU1_SA_DQ<10>")
	)
	(segment
		(start 57.831228 -305.337972)
		(end 57.648348 -305.155092)
		(width 0.18288)
		(layer "In4.Cu")
		(net "M_B_CPU1_SA_DQ<10>")
	)
	(segment
		(start 85.90534 -277.897844)
		(end 85.459316 -277.897844)
		(width 0.088646)
		(layer "In4.Cu")
		(net "M_B_CPU1_SA_DQ<10>")
	)
	(segment
		(start 64.156844 -302.968152)
		(end 64.156844 -302.7299)
		(width 0.18288)
		(layer "In4.Cu")
		(net "M_B_CPU1_SA_DQ<10>")
	)
	(arc
		(start 87.032338 -276.219158)
		(mid 86.829515 -276.419389)
		(end 86.750144 -276.693122)
		(width 0.088646)
		(layer "In4.Cu")
		(net "M_B_CPU1_SA_DQ<10>")
	)
	(arc
		(start 87.68969 -275.08073)
		(mid 87.642011 -275.26363)
		(end 87.511128 -275.400008)
		(width 0.088646)
		(layer "In4.Cu")
		(net "M_B_CPU1_SA_DQ<10>")
	)
	(arc
		(start 88.537796 -274.591272)
		(mid 88.255094 -274.515496)
		(end 87.972392 -274.591272)
		(width 0.088646)
		(layer "In4.Cu")
		(net "M_B_CPU1_SA_DQ<10>")
	)
	(arc
		(start 86.750144 -276.708616)
		(mid 86.702465 -276.891516)
		(end 86.571582 -277.027894)
		(width 0.088646)
		(layer "In4.Cu")
		(net "M_B_CPU1_SA_DQ<10>")
	)
	(arc
		(start 90.417396 -274.591272)
		(mid 90.134694 -274.515496)
		(end 89.851992 -274.591272)
		(width 0.088646)
		(layer "In4.Cu")
		(net "M_B_CPU1_SA_DQ<10>")
	)
	(arc
		(start 87.502238 -275.405088)
		(mid 87.299952 -275.604069)
		(end 87.21979 -275.876258)
		(width 0.088646)
		(layer "In4.Cu")
		(net "M_B_CPU1_SA_DQ<10>")
	)
	(arc
		(start 93.423994 -274.266914)
		(mid 93.161081 -274.035276)
		(end 92.871036 -273.83867)
		(width 0.088646)
		(layer "In4.Cu")
		(net "M_B_CPU1_SA_DQ<10>")
	)
	(arc
		(start 89.851992 -274.591272)
		(mid 89.664794 -274.641415)
		(end 89.477596 -274.591272)
		(width 0.088646)
		(layer "In4.Cu")
		(net "M_B_CPU1_SA_DQ<10>")
	)
	(arc
		(start 88.912192 -274.591272)
		(mid 88.724994 -274.641415)
		(end 88.537796 -274.591272)
		(width 0.088646)
		(layer "In4.Cu")
		(net "M_B_CPU1_SA_DQ<10>")
	)
	(arc
		(start 86.562692 -277.032974)
		(mid 86.359211 -277.233778)
		(end 86.27999 -277.508462)
		(width 0.088646)
		(layer "In4.Cu")
		(net "M_B_CPU1_SA_DQ<10>")
	)
	(arc
		(start 92.201746 -273.77771)
		(mid 92.016129 -273.950676)
		(end 91.924886 -274.187412)
		(width 0.088646)
		(layer "In4.Cu")
		(net "M_B_CPU1_SA_DQ<10>")
	)
	(arc
		(start 92.761054 -273.774154)
		(mid 92.480919 -273.701838)
		(end 92.201746 -273.77771)
		(width 0.088646)
		(layer "In4.Cu")
		(net "M_B_CPU1_SA_DQ<10>")
	)
	(arc
		(start 91.919044 -274.27555)
		(mid 91.866774 -274.457915)
		(end 91.731846 -274.591272)
		(width 0.088646)
		(layer "In4.Cu")
		(net "M_B_CPU1_SA_DQ<10>")
	)
	(arc
		(start 86.101428 -277.841964)
		(mid 86.007253 -277.883473)
		(end 85.90534 -277.897844)
		(width 0.088646)
		(layer "In4.Cu")
		(net "M_B_CPU1_SA_DQ<10>")
	)
	(arc
		(start 90.791792 -274.591272)
		(mid 90.604594 -274.641415)
		(end 90.417396 -274.591272)
		(width 0.088646)
		(layer "In4.Cu")
		(net "M_B_CPU1_SA_DQ<10>")
	)
	(arc
		(start 89.477596 -274.591272)
		(mid 89.194894 -274.515496)
		(end 88.912192 -274.591272)
		(width 0.088646)
		(layer "In4.Cu")
		(net "M_B_CPU1_SA_DQ<10>")
	)
	(arc
		(start 91.347036 -274.585176)
		(mid 91.068604 -274.51533)
		(end 90.791792 -274.591272)
		(width 0.088646)
		(layer "In4.Cu")
		(net "M_B_CPU1_SA_DQ<10>")
	)
	(arc
		(start 87.9602 -274.598384)
		(mid 87.761972 -274.804232)
		(end 87.68969 -275.08073)
		(width 0.088646)
		(layer "In4.Cu")
		(net "M_B_CPU1_SA_DQ<10>")
	)
	(arc
		(start 91.731846 -274.591272)
		(mid 91.544648 -274.641415)
		(end 91.35745 -274.591272)
		(width 0.088646)
		(layer "In4.Cu")
		(net "M_B_CPU1_SA_DQ<10>")
	)
	(arc
		(start 91.924886 -274.187412)
		(mid 91.922192 -274.188528)
		(end 91.921076 -274.191222)
		(width 0.088646)
		(layer "In4.Cu")
		(net "M_B_CPU1_SA_DQ<10>")
	)
	(arc
		(start 92.869512 -273.837908)
		(mid 92.868236 -273.837157)
		(end 92.866972 -273.836384)
		(width 0.088646)
		(layer "In4.Cu")
		(net "M_B_CPU1_SA_DQ<10>")
	)
	(arc
		(start 86.27999 -277.522686)
		(mid 86.232311 -277.705586)
		(end 86.101428 -277.841964)
		(width 0.088646)
		(layer "In4.Cu")
		(net "M_B_CPU1_SA_DQ<10>")
	)
	(arc
		(start 87.21979 -275.8948)
		(mid 87.172111 -276.0777)
		(end 87.041228 -276.214078)
		(width 0.088646)
		(layer "In4.Cu")
		(net "M_B_CPU1_SA_DQ<10>")
	)
	(segment
		(start 46.964346 -316.316614)
		(end 45.859446 -316.316614)
		(width 0.20066)
		(layer "F.Cu")
		(net "M_B_CPU1_SA_DQ<0>")
	)
	(segment
		(start 41.547542 -315.891672)
		(end 41.299638 -315.891672)
		(width 0.101854)
		(layer "F.Cu")
		(net "M_B_CPU1_SA_DQ<0>")
	)
	(segment
		(start 40.520112 -316.093094)
		(end 40.520112 -316.382654)
		(width 0.20066)
		(layer "F.Cu")
		(net "M_B_CPU1_SA_DQ<0>")
	)
	(segment
		(start 45.859446 -316.316614)
		(end 44.490386 -316.316614)
		(width 0.20066)
		(layer "F.Cu")
		(net "M_B_CPU1_SA_DQ<0>")
	)
	(segment
		(start 41.299638 -315.891672)
		(end 41.29151 -315.883544)
		(width 0.101854)
		(layer "F.Cu")
		(net "M_B_CPU1_SA_DQ<0>")
	)
	(segment
		(start 41.29151 -315.883544)
		(end 40.729662 -315.883544)
		(width 0.20066)
		(layer "F.Cu")
		(net "M_B_CPU1_SA_DQ<0>")
	)
	(segment
		(start 40.520112 -316.382654)
		(end 40.347392 -316.555374)
		(width 0.20066)
		(layer "F.Cu")
		(net "M_B_CPU1_SA_DQ<0>")
	)
	(segment
		(start 39.649908 -316.316614)
		(end 38.315646 -316.316614)
		(width 0.20066)
		(layer "F.Cu")
		(net "M_B_CPU1_SA_DQ<0>")
	)
	(segment
		(start 44.065444 -315.891672)
		(end 43.616626 -315.891672)
		(width 0.20066)
		(layer "F.Cu")
		(net "M_B_CPU1_SA_DQ<0>")
	)
	(segment
		(start 39.888668 -316.555374)
		(end 39.649908 -316.316614)
		(width 0.20066)
		(layer "F.Cu")
		(net "M_B_CPU1_SA_DQ<0>")
	)
	(segment
		(start 43.616626 -315.891672)
		(end 41.547542 -315.891672)
		(width 0.1016)
		(layer "F.Cu")
		(net "M_B_CPU1_SA_DQ<0>")
	)
	(segment
		(start 89.194894 -276.172676)
		(end 89.194894 -276.708616)
		(width 0.20066)
		(layer "F.Cu")
		(net "M_B_CPU1_SA_DQ<0>")
	)
	(segment
		(start 40.347392 -316.555374)
		(end 39.888668 -316.555374)
		(width 0.20066)
		(layer "F.Cu")
		(net "M_B_CPU1_SA_DQ<0>")
	)
	(segment
		(start 40.729662 -315.883544)
		(end 40.520112 -316.093094)
		(width 0.20066)
		(layer "F.Cu")
		(net "M_B_CPU1_SA_DQ<0>")
	)
	(segment
		(start 44.490386 -316.316614)
		(end 44.065444 -315.891672)
		(width 0.20066)
		(layer "F.Cu")
		(net "M_B_CPU1_SA_DQ<0>")
	)
	(segment
		(start 89.390982 -278.65578)
		(end 89.382092 -278.66086)
		(width 0.088646)
		(layer "In2.Cu")
		(net "M_B_CPU1_SA_DQ<0>")
	)
	(segment
		(start 84.565998 -285.477966)
		(end 84.37753 -285.932372)
		(width 0.18288)
		(layer "In2.Cu")
		(net "M_B_CPU1_SA_DQ<0>")
	)
	(segment
		(start 85.281262 -281.840686)
		(end 85.066378 -282.05557)
		(width 0.088646)
		(layer "In2.Cu")
		(net "M_B_CPU1_SA_DQ<0>")
	)
	(segment
		(start 88.159844 -280.759662)
		(end 88.159844 -280.778204)
		(width 0.088646)
		(layer "In2.Cu")
		(net "M_B_CPU1_SA_DQ<0>")
	)
	(segment
		(start 61.958982 -316.513972)
		(end 61.733938 -316.739016)
		(width 0.18288)
		(layer "In2.Cu")
		(net "M_B_CPU1_SA_DQ<0>")
	)
	(segment
		(start 88.451182 -280.283412)
		(end 88.442292 -280.288492)
		(width 0.088646)
		(layer "In2.Cu")
		(net "M_B_CPU1_SA_DQ<0>")
	)
	(segment
		(start 88.921082 -279.469596)
		(end 88.912192 -279.474676)
		(width 0.088646)
		(layer "In2.Cu")
		(net "M_B_CPU1_SA_DQ<0>")
	)
	(segment
		(start 67.133978 -314.64377)
		(end 67.133978 -314.956698)
		(width 0.18288)
		(layer "In2.Cu")
		(net "M_B_CPU1_SA_DQ<0>")
	)
	(segment
		(start 59.235086 -316.898274)
		(end 59.078622 -316.74181)
		(width 0.18288)
		(layer "In2.Cu")
		(net "M_B_CPU1_SA_DQ<0>")
	)
	(segment
		(start 89.851992 -277.198074)
		(end 89.860882 -277.203154)
		(width 0.088646)
		(layer "In2.Cu")
		(net "M_B_CPU1_SA_DQ<0>")
	)
	(segment
		(start 87.597996 -281.102562)
		(end 87.583264 -281.093926)
		(width 0.088646)
		(layer "In2.Cu")
		(net "M_B_CPU1_SA_DQ<0>")
	)
	(segment
		(start 52.600606 -316.739016)
		(end 52.135024 -316.273434)
		(width 0.18288)
		(layer "In2.Cu")
		(net "M_B_CPU1_SA_DQ<0>")
	)
	(segment
		(start 52.135024 -316.273434)
		(end 51.875944 -315.647832)
		(width 0.18288)
		(layer "In2.Cu")
		(net "M_B_CPU1_SA_DQ<0>")
	)
	(segment
		(start 86.571582 -281.911298)
		(end 86.562692 -281.916378)
		(width 0.088646)
		(layer "In2.Cu")
		(net "M_B_CPU1_SA_DQ<0>")
	)
	(segment
		(start 83.964272 -286.929068)
		(end 81.461102 -289.42919)
		(width 0.18288)
		(layer "In2.Cu")
		(net "M_B_CPU1_SA_DQ<0>")
	)
	(segment
		(start 89.21369 -276.709886)
		(end 89.481152 -276.709886)
		(width 0.088646)
		(layer "In2.Cu")
		(net "M_B_CPU1_SA_DQ<0>")
	)
	(segment
		(start 89.194894 -276.708616)
		(end 89.21242 -276.708616)
		(width 0.088646)
		(layer "In2.Cu")
		(net "M_B_CPU1_SA_DQ<0>")
	)
	(segment
		(start 55.97144 -316.887352)
		(end 55.823104 -316.739016)
		(width 0.18288)
		(layer "In2.Cu")
		(net "M_B_CPU1_SA_DQ<0>")
	)
	(segment
		(start 85.905594 -281.840686)
		(end 85.281262 -281.840686)
		(width 0.088646)
		(layer "In2.Cu")
		(net "M_B_CPU1_SA_DQ<0>")
	)
	(segment
		(start 89.860882 -277.84171)
		(end 89.851992 -277.84679)
		(width 0.088646)
		(layer "In2.Cu")
		(net "M_B_CPU1_SA_DQ<0>")
	)
	(segment
		(start 58.236866 -316.641226)
		(end 56.770524 -316.641226)
		(width 0.18288)
		(layer "In2.Cu")
		(net "M_B_CPU1_SA_DQ<0>")
	)
	(segment
		(start 51.2699 -315.041788)
		(end 50.318924 -315.041788)
		(width 0.18288)
		(layer "In2.Cu")
		(net "M_B_CPU1_SA_DQ<0>")
	)
	(segment
		(start 88.629744 -279.954228)
		(end 88.629744 -279.964134)
		(width 0.088646)
		(layer "In2.Cu")
		(net "M_B_CPU1_SA_DQ<0>")
	)
	(segment
		(start 55.823104 -316.739016)
		(end 52.600606 -316.739016)
		(width 0.18288)
		(layer "In2.Cu")
		(net "M_B_CPU1_SA_DQ<0>")
	)
	(segment
		(start 85.066378 -282.05557)
		(end 84.565998 -282.55595)
		(width 0.18288)
		(layer "In2.Cu")
		(net "M_B_CPU1_SA_DQ<0>")
	)
	(segment
		(start 66.238628 -315.852048)
		(end 63.748666 -315.852048)
		(width 0.18288)
		(layer "In2.Cu")
		(net "M_B_CPU1_SA_DQ<0>")
	)
	(segment
		(start 58.33745 -316.74181)
		(end 58.236866 -316.641226)
		(width 0.18288)
		(layer "In2.Cu")
		(net "M_B_CPU1_SA_DQ<0>")
	)
	(segment
		(start 89.481152 -276.709886)
		(end 89.57818 -276.806914)
		(width 0.088646)
		(layer "In2.Cu")
		(net "M_B_CPU1_SA_DQ<0>")
	)
	(segment
		(start 59.624722 -316.739016)
		(end 59.465464 -316.898274)
		(width 0.18288)
		(layer "In2.Cu")
		(net "M_B_CPU1_SA_DQ<0>")
	)
	(segment
		(start 89.21242 -276.708616)
		(end 89.21369 -276.709886)
		(width 0.088646)
		(layer "In2.Cu")
		(net "M_B_CPU1_SA_DQ<0>")
	)
	(segment
		(start 76.923138 -300.376844)
		(end 76.28636 -303.578006)
		(width 0.18288)
		(layer "In2.Cu")
		(net "M_B_CPU1_SA_DQ<0>")
	)
	(segment
		(start 50.318924 -315.041788)
		(end 50.256948 -315.103764)
		(width 0.18288)
		(layer "In2.Cu")
		(net "M_B_CPU1_SA_DQ<0>")
	)
	(segment
		(start 67.133978 -314.956698)
		(end 66.238628 -315.852048)
		(width 0.18288)
		(layer "In2.Cu")
		(net "M_B_CPU1_SA_DQ<0>")
	)
	(segment
		(start 59.078622 -316.74181)
		(end 58.33745 -316.74181)
		(width 0.18288)
		(layer "In2.Cu")
		(net "M_B_CPU1_SA_DQ<0>")
	)
	(segment
		(start 61.733938 -316.739016)
		(end 59.624722 -316.739016)
		(width 0.18288)
		(layer "In2.Cu")
		(net "M_B_CPU1_SA_DQ<0>")
	)
	(segment
		(start 56.524398 -316.887352)
		(end 55.97144 -316.887352)
		(width 0.18288)
		(layer "In2.Cu")
		(net "M_B_CPU1_SA_DQ<0>")
	)
	(segment
		(start 63.086742 -316.513972)
		(end 61.958982 -316.513972)
		(width 0.18288)
		(layer "In2.Cu")
		(net "M_B_CPU1_SA_DQ<0>")
	)
	(segment
		(start 56.770524 -316.641226)
		(end 56.524398 -316.887352)
		(width 0.18288)
		(layer "In2.Cu")
		(net "M_B_CPU1_SA_DQ<0>")
	)
	(segment
		(start 50.256948 -315.103764)
		(end 48.779684 -315.103764)
		(width 0.18288)
		(layer "In2.Cu")
		(net "M_B_CPU1_SA_DQ<0>")
	)
	(segment
		(start 59.465464 -316.898274)
		(end 59.235086 -316.898274)
		(width 0.18288)
		(layer "In2.Cu")
		(net "M_B_CPU1_SA_DQ<0>")
	)
	(segment
		(start 87.981282 -281.097482)
		(end 87.972392 -281.102562)
		(width 0.088646)
		(layer "In2.Cu")
		(net "M_B_CPU1_SA_DQ<0>")
	)
	(segment
		(start 63.748666 -315.852048)
		(end 63.086742 -316.513972)
		(width 0.18288)
		(layer "In2.Cu")
		(net "M_B_CPU1_SA_DQ<0>")
	)
	(segment
		(start 87.032592 -281.102562)
		(end 87.026496 -281.106118)
		(width 0.088646)
		(layer "In2.Cu")
		(net "M_B_CPU1_SA_DQ<0>")
	)
	(segment
		(start 84.565998 -282.55595)
		(end 84.565998 -285.477966)
		(width 0.18288)
		(layer "In2.Cu")
		(net "M_B_CPU1_SA_DQ<0>")
	)
	(segment
		(start 74.933048 -306.8447)
		(end 67.133978 -314.64377)
		(width 0.18288)
		(layer "In2.Cu")
		(net "M_B_CPU1_SA_DQ<0>")
	)
	(segment
		(start 51.875944 -315.647832)
		(end 51.2699 -315.041788)
		(width 0.18288)
		(layer "In2.Cu")
		(net "M_B_CPU1_SA_DQ<0>")
	)
	(segment
		(start 48.779684 -315.103764)
		(end 46.964346 -316.316614)
		(width 0.18288)
		(layer "In2.Cu")
		(net "M_B_CPU1_SA_DQ<0>")
	)
	(segment
		(start 76.28636 -303.578006)
		(end 74.933048 -306.8447)
		(width 0.18288)
		(layer "In2.Cu")
		(net "M_B_CPU1_SA_DQ<0>")
	)
	(segment
		(start 89.099644 -279.140412)
		(end 89.099644 -279.150318)
		(width 0.088646)
		(layer "In2.Cu")
		(net "M_B_CPU1_SA_DQ<0>")
	)
	(segment
		(start 84.37753 -285.932372)
		(end 83.964272 -286.929068)
		(width 0.18288)
		(layer "In2.Cu")
		(net "M_B_CPU1_SA_DQ<0>")
	)
	(segment
		(start 89.569544 -278.31796)
		(end 89.569544 -278.336502)
		(width 0.088646)
		(layer "In2.Cu")
		(net "M_B_CPU1_SA_DQ<0>")
	)
	(segment
		(start 81.461102 -289.42919)
		(end 76.923138 -300.376844)
		(width 0.18288)
		(layer "In2.Cu")
		(net "M_B_CPU1_SA_DQ<0>")
	)
	(arc
		(start 89.57818 -276.806914)
		(mid 89.671788 -277.032789)
		(end 89.851992 -277.198074)
		(width 0.088646)
		(layer "In2.Cu")
		(net "M_B_CPU1_SA_DQ<0>")
	)
	(arc
		(start 89.860882 -277.203154)
		(mid 90.039479 -277.522432)
		(end 89.860882 -277.84171)
		(width 0.088646)
		(layer "In2.Cu")
		(net "M_B_CPU1_SA_DQ<0>")
	)
	(arc
		(start 88.159844 -280.778204)
		(mid 88.112165 -280.961104)
		(end 87.981282 -281.097482)
		(width 0.088646)
		(layer "In2.Cu")
		(net "M_B_CPU1_SA_DQ<0>")
	)
	(arc
		(start 87.583264 -281.093926)
		(mid 87.306789 -281.026606)
		(end 87.032592 -281.102562)
		(width 0.088646)
		(layer "In2.Cu")
		(net "M_B_CPU1_SA_DQ<0>")
	)
	(arc
		(start 88.912192 -279.474676)
		(mid 88.707857 -279.677281)
		(end 88.629744 -279.954228)
		(width 0.088646)
		(layer "In2.Cu")
		(net "M_B_CPU1_SA_DQ<0>")
	)
	(arc
		(start 88.442292 -280.288492)
		(mid 88.240006 -280.487473)
		(end 88.159844 -280.759662)
		(width 0.088646)
		(layer "In2.Cu")
		(net "M_B_CPU1_SA_DQ<0>")
	)
	(arc
		(start 86.562692 -281.916378)
		(mid 86.375494 -281.966521)
		(end 86.188296 -281.916378)
		(width 0.088646)
		(layer "In2.Cu")
		(net "M_B_CPU1_SA_DQ<0>")
	)
	(arc
		(start 89.569544 -278.336502)
		(mid 89.521865 -278.519402)
		(end 89.390982 -278.65578)
		(width 0.088646)
		(layer "In2.Cu")
		(net "M_B_CPU1_SA_DQ<0>")
	)
	(arc
		(start 88.629744 -279.964134)
		(mid 88.582065 -280.147034)
		(end 88.451182 -280.283412)
		(width 0.088646)
		(layer "In2.Cu")
		(net "M_B_CPU1_SA_DQ<0>")
	)
	(arc
		(start 89.382092 -278.66086)
		(mid 89.177757 -278.863465)
		(end 89.099644 -279.140412)
		(width 0.088646)
		(layer "In2.Cu")
		(net "M_B_CPU1_SA_DQ<0>")
	)
	(arc
		(start 86.188296 -281.916378)
		(mid 86.051927 -281.859936)
		(end 85.905594 -281.840686)
		(width 0.088646)
		(layer "In2.Cu")
		(net "M_B_CPU1_SA_DQ<0>")
	)
	(arc
		(start 86.750144 -281.59202)
		(mid 86.702465 -281.77492)
		(end 86.571582 -281.911298)
		(width 0.088646)
		(layer "In2.Cu")
		(net "M_B_CPU1_SA_DQ<0>")
	)
	(arc
		(start 87.026496 -281.106118)
		(mid 86.824083 -281.312531)
		(end 86.750144 -281.59202)
		(width 0.088646)
		(layer "In2.Cu")
		(net "M_B_CPU1_SA_DQ<0>")
	)
	(arc
		(start 87.972392 -281.102562)
		(mid 87.785194 -281.152705)
		(end 87.597996 -281.102562)
		(width 0.088646)
		(layer "In2.Cu")
		(net "M_B_CPU1_SA_DQ<0>")
	)
	(arc
		(start 89.099644 -279.150318)
		(mid 89.051965 -279.333218)
		(end 88.921082 -279.469596)
		(width 0.088646)
		(layer "In2.Cu")
		(net "M_B_CPU1_SA_DQ<0>")
	)
	(arc
		(start 89.851992 -277.84679)
		(mid 89.649706 -278.045771)
		(end 89.569544 -278.31796)
		(width 0.088646)
		(layer "In2.Cu")
		(net "M_B_CPU1_SA_DQ<0>")
	)
	(segment
		(start 90.604848 -255.825498)
		(end 90.604848 -256.361184)
		(width 0.20066)
		(layer "F.Cu")
		(net "M_B_CPU1_SA_CS_N<3>")
	)
	(segment
		(start 90.604848 -256.361184)
		(end 90.604594 -256.361438)
		(width 0.20066)
		(layer "F.Cu")
		(net "M_B_CPU1_SA_CS_N<3>")
	)
	(segment
		(start 49.959514 -267.016738)
		(end 51.089814 -267.016738)
		(width 0.20066)
		(layer "F.Cu")
		(net "M_B_CPU1_SA_CS_N<3>")
	)
	(segment
		(start 83.876134 -256.476246)
		(end 82.973418 -256.476246)
		(width 0.18288)
		(layer "In2.Cu")
		(net "M_B_CPU1_SA_CS_N<3>")
	)
	(segment
		(start 61.492638 -265.272266)
		(end 60.534042 -265.272266)
		(width 0.18288)
		(layer "In2.Cu")
		(net "M_B_CPU1_SA_CS_N<3>")
	)
	(segment
		(start 83.987894 -256.476246)
		(end 83.876134 -256.476246)
		(width 0.088646)
		(layer "In2.Cu")
		(net "M_B_CPU1_SA_CS_N<3>")
	)
	(segment
		(start 62.961774 -264.912348)
		(end 62.618112 -264.912348)
		(width 0.18288)
		(layer "In2.Cu")
		(net "M_B_CPU1_SA_CS_N<3>")
	)
	(segment
		(start 62.618112 -264.912348)
		(end 62.310518 -264.604754)
		(width 0.18288)
		(layer "In2.Cu")
		(net "M_B_CPU1_SA_CS_N<3>")
	)
	(segment
		(start 61.784738 -264.980166)
		(end 61.492638 -265.272266)
		(width 0.18288)
		(layer "In2.Cu")
		(net "M_B_CPU1_SA_CS_N<3>")
	)
	(segment
		(start 56.576214 -265.570462)
		(end 56.323738 -265.570462)
		(width 0.18288)
		(layer "In2.Cu")
		(net "M_B_CPU1_SA_CS_N<3>")
	)
	(segment
		(start 65.234058 -264.410952)
		(end 64.490346 -264.410952)
		(width 0.18288)
		(layer "In2.Cu")
		(net "M_B_CPU1_SA_CS_N<3>")
	)
	(segment
		(start 74.6887 -259.365496)
		(end 68.006722 -262.13308)
		(width 0.18288)
		(layer "In2.Cu")
		(net "M_B_CPU1_SA_CS_N<3>")
	)
	(segment
		(start 84.63534 -256.604262)
		(end 84.536534 -256.505456)
		(width 0.088646)
		(layer "In2.Cu")
		(net "M_B_CPU1_SA_CS_N<3>")
	)
	(segment
		(start 59.227212 -265.210798)
		(end 59.227212 -265.43508)
		(width 0.18288)
		(layer "In2.Cu")
		(net "M_B_CPU1_SA_CS_N<3>")
	)
	(segment
		(start 53.827426 -267.06068)
		(end 52.996846 -267.06068)
		(width 0.18288)
		(layer "In2.Cu")
		(net "M_B_CPU1_SA_CS_N<3>")
	)
	(segment
		(start 55.743602 -266.47902)
		(end 54.653942 -267.56868)
		(width 0.18288)
		(layer "In2.Cu")
		(net "M_B_CPU1_SA_CS_N<3>")
	)
	(segment
		(start 75.39355 -258.660646)
		(end 74.6887 -259.365496)
		(width 0.18288)
		(layer "In2.Cu")
		(net "M_B_CPU1_SA_CS_N<3>")
	)
	(segment
		(start 61.784738 -264.804652)
		(end 61.784738 -264.980166)
		(width 0.18288)
		(layer "In2.Cu")
		(net "M_B_CPU1_SA_CS_N<3>")
	)
	(segment
		(start 64.087502 -264.008108)
		(end 63.485522 -264.008108)
		(width 0.18288)
		(layer "In2.Cu")
		(net "M_B_CPU1_SA_CS_N<3>")
	)
	(segment
		(start 90.604594 -256.361438)
		(end 90.44813 -256.632456)
		(width 0.088646)
		(layer "In2.Cu")
		(net "M_B_CPU1_SA_CS_N<3>")
	)
	(segment
		(start 55.743602 -266.150598)
		(end 55.743602 -266.47902)
		(width 0.18288)
		(layer "In2.Cu")
		(net "M_B_CPU1_SA_CS_N<3>")
	)
	(segment
		(start 65.625218 -264.019792)
		(end 65.234058 -264.410952)
		(width 0.18288)
		(layer "In2.Cu")
		(net "M_B_CPU1_SA_CS_N<3>")
	)
	(segment
		(start 84.536534 -256.505456)
		(end 84.536534 -256.37744)
		(width 0.088646)
		(layer "In2.Cu")
		(net "M_B_CPU1_SA_CS_N<3>")
	)
	(segment
		(start 90.44813 -256.632456)
		(end 90.358976 -256.656332)
		(width 0.088646)
		(layer "In2.Cu")
		(net "M_B_CPU1_SA_CS_N<3>")
	)
	(segment
		(start 67.180968 -263.289542)
		(end 66.450718 -264.019792)
		(width 0.18288)
		(layer "In2.Cu")
		(net "M_B_CPU1_SA_CS_N<3>")
	)
	(segment
		(start 58.944002 -265.71829)
		(end 58.351928 -265.71829)
		(width 0.18288)
		(layer "In2.Cu")
		(net "M_B_CPU1_SA_CS_N<3>")
	)
	(segment
		(start 59.713368 -264.724642)
		(end 59.227212 -265.210798)
		(width 0.18288)
		(layer "In2.Cu")
		(net "M_B_CPU1_SA_CS_N<3>")
	)
	(segment
		(start 82.973418 -256.476246)
		(end 80.789018 -258.660646)
		(width 0.18288)
		(layer "In2.Cu")
		(net "M_B_CPU1_SA_CS_N<3>")
	)
	(segment
		(start 57.952894 -266.117324)
		(end 56.906668 -266.117324)
		(width 0.18288)
		(layer "In2.Cu")
		(net "M_B_CPU1_SA_CS_N<3>")
	)
	(segment
		(start 52.575714 -267.481812)
		(end 52.151026 -267.481812)
		(width 0.18288)
		(layer "In2.Cu")
		(net "M_B_CPU1_SA_CS_N<3>")
	)
	(segment
		(start 64.490346 -264.410952)
		(end 64.087502 -264.008108)
		(width 0.18288)
		(layer "In2.Cu")
		(net "M_B_CPU1_SA_CS_N<3>")
	)
	(segment
		(start 84.161122 -256.303018)
		(end 83.987894 -256.476246)
		(width 0.088646)
		(layer "In2.Cu")
		(net "M_B_CPU1_SA_CS_N<3>")
	)
	(segment
		(start 52.996846 -267.06068)
		(end 52.575714 -267.481812)
		(width 0.18288)
		(layer "In2.Cu")
		(net "M_B_CPU1_SA_CS_N<3>")
	)
	(segment
		(start 58.351928 -265.71829)
		(end 57.952894 -266.117324)
		(width 0.18288)
		(layer "In2.Cu")
		(net "M_B_CPU1_SA_CS_N<3>")
	)
	(segment
		(start 60.534042 -265.272266)
		(end 59.986418 -264.724642)
		(width 0.18288)
		(layer "In2.Cu")
		(net "M_B_CPU1_SA_CS_N<3>")
	)
	(segment
		(start 54.653942 -267.56868)
		(end 54.335426 -267.56868)
		(width 0.18288)
		(layer "In2.Cu")
		(net "M_B_CPU1_SA_CS_N<3>")
	)
	(segment
		(start 54.335426 -267.56868)
		(end 53.827426 -267.06068)
		(width 0.18288)
		(layer "In2.Cu")
		(net "M_B_CPU1_SA_CS_N<3>")
	)
	(segment
		(start 80.789018 -258.660646)
		(end 75.39355 -258.660646)
		(width 0.18288)
		(layer "In2.Cu")
		(net "M_B_CPU1_SA_CS_N<3>")
	)
	(segment
		(start 59.986418 -264.724642)
		(end 59.713368 -264.724642)
		(width 0.18288)
		(layer "In2.Cu")
		(net "M_B_CPU1_SA_CS_N<3>")
	)
	(segment
		(start 56.792876 -266.003532)
		(end 56.792876 -265.787124)
		(width 0.18288)
		(layer "In2.Cu")
		(net "M_B_CPU1_SA_CS_N<3>")
	)
	(segment
		(start 67.180968 -262.958834)
		(end 67.180968 -263.289542)
		(width 0.18288)
		(layer "In2.Cu")
		(net "M_B_CPU1_SA_CS_N<3>")
	)
	(segment
		(start 59.227212 -265.43508)
		(end 58.944002 -265.71829)
		(width 0.18288)
		(layer "In2.Cu")
		(net "M_B_CPU1_SA_CS_N<3>")
	)
	(segment
		(start 61.984636 -264.604754)
		(end 61.784738 -264.804652)
		(width 0.18288)
		(layer "In2.Cu")
		(net "M_B_CPU1_SA_CS_N<3>")
	)
	(segment
		(start 63.485522 -264.008108)
		(end 63.27394 -264.21969)
		(width 0.18288)
		(layer "In2.Cu")
		(net "M_B_CPU1_SA_CS_N<3>")
	)
	(segment
		(start 84.91855 -256.721102)
		(end 84.63534 -256.604262)
		(width 0.088646)
		(layer "In2.Cu")
		(net "M_B_CPU1_SA_CS_N<3>")
	)
	(segment
		(start 68.006722 -262.13308)
		(end 67.180968 -262.958834)
		(width 0.18288)
		(layer "In2.Cu")
		(net "M_B_CPU1_SA_CS_N<3>")
	)
	(segment
		(start 84.536534 -256.37744)
		(end 84.462112 -256.303018)
		(width 0.088646)
		(layer "In2.Cu")
		(net "M_B_CPU1_SA_CS_N<3>")
	)
	(segment
		(start 63.27394 -264.600182)
		(end 62.961774 -264.912348)
		(width 0.18288)
		(layer "In2.Cu")
		(net "M_B_CPU1_SA_CS_N<3>")
	)
	(segment
		(start 62.310518 -264.604754)
		(end 61.984636 -264.604754)
		(width 0.18288)
		(layer "In2.Cu")
		(net "M_B_CPU1_SA_CS_N<3>")
	)
	(segment
		(start 56.906668 -266.117324)
		(end 56.792876 -266.003532)
		(width 0.18288)
		(layer "In2.Cu")
		(net "M_B_CPU1_SA_CS_N<3>")
	)
	(segment
		(start 56.323738 -265.570462)
		(end 55.743602 -266.150598)
		(width 0.18288)
		(layer "In2.Cu")
		(net "M_B_CPU1_SA_CS_N<3>")
	)
	(segment
		(start 51.685952 -267.016738)
		(end 51.089814 -267.016738)
		(width 0.18288)
		(layer "In2.Cu")
		(net "M_B_CPU1_SA_CS_N<3>")
	)
	(segment
		(start 56.792876 -265.787124)
		(end 56.576214 -265.570462)
		(width 0.18288)
		(layer "In2.Cu")
		(net "M_B_CPU1_SA_CS_N<3>")
	)
	(segment
		(start 63.27394 -264.21969)
		(end 63.27394 -264.600182)
		(width 0.18288)
		(layer "In2.Cu")
		(net "M_B_CPU1_SA_CS_N<3>")
	)
	(segment
		(start 84.462112 -256.303018)
		(end 84.161122 -256.303018)
		(width 0.088646)
		(layer "In2.Cu")
		(net "M_B_CPU1_SA_CS_N<3>")
	)
	(segment
		(start 52.151026 -267.481812)
		(end 51.685952 -267.016738)
		(width 0.18288)
		(layer "In2.Cu")
		(net "M_B_CPU1_SA_CS_N<3>")
	)
	(segment
		(start 66.450718 -264.019792)
		(end 65.625218 -264.019792)
		(width 0.18288)
		(layer "In2.Cu")
		(net "M_B_CPU1_SA_CS_N<3>")
	)
	(arc
		(start 87.032592 -256.685796)
		(mid 86.845394 -256.735939)
		(end 86.658196 -256.685796)
		(width 0.088646)
		(layer "In2.Cu")
		(net "M_B_CPU1_SA_CS_N<3>")
	)
	(arc
		(start 86.092792 -256.685796)
		(mid 85.905594 -256.735939)
		(end 85.718396 -256.685796)
		(width 0.088646)
		(layer "In2.Cu")
		(net "M_B_CPU1_SA_CS_N<3>")
	)
	(arc
		(start 85.718396 -256.685796)
		(mid 85.435694 -256.61002)
		(end 85.152992 -256.685796)
		(width 0.088646)
		(layer "In2.Cu")
		(net "M_B_CPU1_SA_CS_N<3>")
	)
	(arc
		(start 86.658196 -256.685796)
		(mid 86.375494 -256.61002)
		(end 86.092792 -256.685796)
		(width 0.088646)
		(layer "In2.Cu")
		(net "M_B_CPU1_SA_CS_N<3>")
	)
	(arc
		(start 87.597996 -256.685796)
		(mid 87.315294 -256.61002)
		(end 87.032592 -256.685796)
		(width 0.088646)
		(layer "In2.Cu")
		(net "M_B_CPU1_SA_CS_N<3>")
	)
	(arc
		(start 89.477596 -256.685796)
		(mid 89.194894 -256.61002)
		(end 88.912192 -256.685796)
		(width 0.088646)
		(layer "In2.Cu")
		(net "M_B_CPU1_SA_CS_N<3>")
	)
	(arc
		(start 85.006434 -256.733802)
		(mid 84.961698 -256.732966)
		(end 84.91855 -256.721102)
		(width 0.088646)
		(layer "In2.Cu")
		(net "M_B_CPU1_SA_CS_N<3>")
	)
	(arc
		(start 90.358976 -256.656332)
		(mid 90.101977 -256.610885)
		(end 89.851992 -256.685796)
		(width 0.088646)
		(layer "In2.Cu")
		(net "M_B_CPU1_SA_CS_N<3>")
	)
	(arc
		(start 85.152992 -256.685796)
		(mid 85.082213 -256.717435)
		(end 85.006434 -256.733802)
		(width 0.088646)
		(layer "In2.Cu")
		(net "M_B_CPU1_SA_CS_N<3>")
	)
	(arc
		(start 89.851992 -256.685796)
		(mid 89.664794 -256.735939)
		(end 89.477596 -256.685796)
		(width 0.088646)
		(layer "In2.Cu")
		(net "M_B_CPU1_SA_CS_N<3>")
	)
	(arc
		(start 88.912192 -256.685796)
		(mid 88.724994 -256.735939)
		(end 88.537796 -256.685796)
		(width 0.088646)
		(layer "In2.Cu")
		(net "M_B_CPU1_SA_CS_N<3>")
	)
	(arc
		(start 87.972392 -256.685796)
		(mid 87.785194 -256.735939)
		(end 87.597996 -256.685796)
		(width 0.088646)
		(layer "In2.Cu")
		(net "M_B_CPU1_SA_CS_N<3>")
	)
	(arc
		(start 88.537796 -256.685796)
		(mid 88.255094 -256.61002)
		(end 87.972392 -256.685796)
		(width 0.088646)
		(layer "In2.Cu")
		(net "M_B_CPU1_SA_CS_N<3>")
	)
	(segment
		(start 45.859446 -267.866622)
		(end 46.964346 -267.866622)
		(width 0.20066)
		(layer "F.Cu")
		(net "M_B_CPU1_SA_CS_N<2>")
	)
	(segment
		(start 90.134694 -257.175254)
		(end 90.134694 -256.639314)
		(width 0.20066)
		(layer "F.Cu")
		(net "M_B_CPU1_SA_CS_N<2>")
	)
	(segment
		(start 75.76693 -259.006086)
		(end 74.961496 -259.81152)
		(width 0.18288)
		(layer "In2.Cu")
		(net "M_B_CPU1_SA_CS_N<2>")
	)
	(segment
		(start 62.193932 -265.780266)
		(end 59.62904 -265.780266)
		(width 0.18288)
		(layer "In2.Cu")
		(net "M_B_CPU1_SA_CS_N<2>")
	)
	(segment
		(start 47.259494 -267.571474)
		(end 46.964346 -267.866622)
		(width 0.18288)
		(layer "In2.Cu")
		(net "M_B_CPU1_SA_CS_N<2>")
	)
	(segment
		(start 48.690022 -267.3985)
		(end 48.15332 -267.935202)
		(width 0.18288)
		(layer "In2.Cu")
		(net "M_B_CPU1_SA_CS_N<2>")
	)
	(segment
		(start 58.783982 -266.625324)
		(end 56.316118 -266.625324)
		(width 0.18288)
		(layer "In2.Cu")
		(net "M_B_CPU1_SA_CS_N<2>")
	)
	(segment
		(start 50.23866 -267.601954)
		(end 49.271428 -267.601954)
		(width 0.18288)
		(layer "In2.Cu")
		(net "M_B_CPU1_SA_CS_N<2>")
	)
	(segment
		(start 50.398934 -267.44168)
		(end 50.23866 -267.601954)
		(width 0.18288)
		(layer "In2.Cu")
		(net "M_B_CPU1_SA_CS_N<2>")
	)
	(segment
		(start 84.58581 -256.824734)
		(end 83.876134 -256.824734)
		(width 0.088646)
		(layer "In2.Cu")
		(net "M_B_CPU1_SA_CS_N<2>")
	)
	(segment
		(start 83.113626 -256.824734)
		(end 80.932274 -259.006086)
		(width 0.18288)
		(layer "In2.Cu")
		(net "M_B_CPU1_SA_CS_N<2>")
	)
	(segment
		(start 52.885594 -268.243304)
		(end 52.107846 -268.243304)
		(width 0.18288)
		(layer "In2.Cu")
		(net "M_B_CPU1_SA_CS_N<2>")
	)
	(segment
		(start 47.516288 -267.571474)
		(end 47.259494 -267.571474)
		(width 0.18288)
		(layer "In2.Cu")
		(net "M_B_CPU1_SA_CS_N<2>")
	)
	(segment
		(start 54.698138 -268.243304)
		(end 53.95214 -268.243304)
		(width 0.18288)
		(layer "In2.Cu")
		(net "M_B_CPU1_SA_CS_N<2>")
	)
	(segment
		(start 74.961496 -259.81152)
		(end 68.906136 -262.318754)
		(width 0.18288)
		(layer "In2.Cu")
		(net "M_B_CPU1_SA_CS_N<2>")
	)
	(segment
		(start 49.271428 -267.601954)
		(end 49.067974 -267.3985)
		(width 0.18288)
		(layer "In2.Cu")
		(net "M_B_CPU1_SA_CS_N<2>")
	)
	(segment
		(start 83.876134 -256.824734)
		(end 83.113626 -256.824734)
		(width 0.18288)
		(layer "In2.Cu")
		(net "M_B_CPU1_SA_CS_N<2>")
	)
	(segment
		(start 53.95214 -268.243304)
		(end 53.589174 -268.60627)
		(width 0.18288)
		(layer "In2.Cu")
		(net "M_B_CPU1_SA_CS_N<2>")
	)
	(segment
		(start 51.306222 -267.44168)
		(end 50.398934 -267.44168)
		(width 0.18288)
		(layer "In2.Cu")
		(net "M_B_CPU1_SA_CS_N<2>")
	)
	(segment
		(start 56.316118 -266.625324)
		(end 54.698138 -268.243304)
		(width 0.18288)
		(layer "In2.Cu")
		(net "M_B_CPU1_SA_CS_N<2>")
	)
	(segment
		(start 47.880016 -267.935202)
		(end 47.516288 -267.571474)
		(width 0.18288)
		(layer "In2.Cu")
		(net "M_B_CPU1_SA_CS_N<2>")
	)
	(segment
		(start 48.15332 -267.935202)
		(end 47.880016 -267.935202)
		(width 0.18288)
		(layer "In2.Cu")
		(net "M_B_CPU1_SA_CS_N<2>")
	)
	(segment
		(start 66.304414 -264.918952)
		(end 64.27343 -264.918952)
		(width 0.18288)
		(layer "In2.Cu")
		(net "M_B_CPU1_SA_CS_N<2>")
	)
	(segment
		(start 52.107846 -268.243304)
		(end 51.306222 -267.44168)
		(width 0.18288)
		(layer "In2.Cu")
		(net "M_B_CPU1_SA_CS_N<2>")
	)
	(segment
		(start 59.62904 -265.780266)
		(end 58.783982 -266.625324)
		(width 0.18288)
		(layer "In2.Cu")
		(net "M_B_CPU1_SA_CS_N<2>")
	)
	(segment
		(start 68.906136 -262.318754)
		(end 66.304414 -264.918952)
		(width 0.18288)
		(layer "In2.Cu")
		(net "M_B_CPU1_SA_CS_N<2>")
	)
	(segment
		(start 90.134694 -257.175254)
		(end 90.291158 -256.904236)
		(width 0.088646)
		(layer "In2.Cu")
		(net "M_B_CPU1_SA_CS_N<2>")
	)
	(segment
		(start 53.24856 -268.60627)
		(end 52.885594 -268.243304)
		(width 0.18288)
		(layer "In2.Cu")
		(net "M_B_CPU1_SA_CS_N<2>")
	)
	(segment
		(start 64.27343 -264.918952)
		(end 62.193932 -265.780266)
		(width 0.18288)
		(layer "In2.Cu")
		(net "M_B_CPU1_SA_CS_N<2>")
	)
	(segment
		(start 53.589174 -268.60627)
		(end 53.24856 -268.60627)
		(width 0.18288)
		(layer "In2.Cu")
		(net "M_B_CPU1_SA_CS_N<2>")
	)
	(segment
		(start 49.067974 -267.3985)
		(end 48.690022 -267.3985)
		(width 0.18288)
		(layer "In2.Cu")
		(net "M_B_CPU1_SA_CS_N<2>")
	)
	(segment
		(start 80.932274 -259.006086)
		(end 75.76693 -259.006086)
		(width 0.18288)
		(layer "In2.Cu")
		(net "M_B_CPU1_SA_CS_N<2>")
	)
	(segment
		(start 90.291158 -256.904236)
		(end 90.270076 -256.826258)
		(width 0.088646)
		(layer "In2.Cu")
		(net "M_B_CPU1_SA_CS_N<2>")
	)
	(arc
		(start 87.128096 -256.850896)
		(mid 86.845394 -256.926672)
		(end 86.562692 -256.850896)
		(width 0.088646)
		(layer "In2.Cu")
		(net "M_B_CPU1_SA_CS_N<2>")
	)
	(arc
		(start 84.683092 -256.850896)
		(mid 84.636177 -256.831399)
		(end 84.58581 -256.824734)
		(width 0.088646)
		(layer "In2.Cu")
		(net "M_B_CPU1_SA_CS_N<2>")
	)
	(arc
		(start 89.947496 -256.850896)
		(mid 89.664794 -256.926672)
		(end 89.382092 -256.850896)
		(width 0.088646)
		(layer "In2.Cu")
		(net "M_B_CPU1_SA_CS_N<2>")
	)
	(arc
		(start 88.067896 -256.850896)
		(mid 87.785194 -256.926672)
		(end 87.502492 -256.850896)
		(width 0.088646)
		(layer "In2.Cu")
		(net "M_B_CPU1_SA_CS_N<2>")
	)
	(arc
		(start 87.502492 -256.850896)
		(mid 87.315294 -256.800753)
		(end 87.128096 -256.850896)
		(width 0.088646)
		(layer "In2.Cu")
		(net "M_B_CPU1_SA_CS_N<2>")
	)
	(arc
		(start 88.442292 -256.850896)
		(mid 88.255094 -256.800753)
		(end 88.067896 -256.850896)
		(width 0.088646)
		(layer "In2.Cu")
		(net "M_B_CPU1_SA_CS_N<2>")
	)
	(arc
		(start 85.622892 -256.850896)
		(mid 85.435694 -256.800753)
		(end 85.248496 -256.850896)
		(width 0.088646)
		(layer "In2.Cu")
		(net "M_B_CPU1_SA_CS_N<2>")
	)
	(arc
		(start 90.270076 -256.826258)
		(mid 90.10598 -256.801911)
		(end 89.947496 -256.850896)
		(width 0.088646)
		(layer "In2.Cu")
		(net "M_B_CPU1_SA_CS_N<2>")
	)
	(arc
		(start 86.562692 -256.850896)
		(mid 86.375494 -256.800753)
		(end 86.188296 -256.850896)
		(width 0.088646)
		(layer "In2.Cu")
		(net "M_B_CPU1_SA_CS_N<2>")
	)
	(arc
		(start 85.248496 -256.850896)
		(mid 84.965794 -256.926672)
		(end 84.683092 -256.850896)
		(width 0.088646)
		(layer "In2.Cu")
		(net "M_B_CPU1_SA_CS_N<2>")
	)
	(arc
		(start 89.382092 -256.850896)
		(mid 89.194894 -256.800753)
		(end 89.007696 -256.850896)
		(width 0.088646)
		(layer "In2.Cu")
		(net "M_B_CPU1_SA_CS_N<2>")
	)
	(arc
		(start 86.188296 -256.850896)
		(mid 85.905594 -256.926672)
		(end 85.622892 -256.850896)
		(width 0.088646)
		(layer "In2.Cu")
		(net "M_B_CPU1_SA_CS_N<2>")
	)
	(arc
		(start 89.007696 -256.850896)
		(mid 88.724994 -256.926672)
		(end 88.442292 -256.850896)
		(width 0.088646)
		(layer "In2.Cu")
		(net "M_B_CPU1_SA_CS_N<2>")
	)
	(segment
		(start 88.725248 -256.361184)
		(end 88.724994 -256.361438)
		(width 0.20066)
		(layer "F.Cu")
		(net "M_B_CPU1_SA_CS_N<1>")
	)
	(segment
		(start 88.725248 -255.825498)
		(end 88.725248 -256.361184)
		(width 0.20066)
		(layer "F.Cu")
		(net "M_B_CPU1_SA_CS_N<1>")
	)
	(segment
		(start 42.415714 -267.016738)
		(end 43.520614 -267.016738)
		(width 0.20066)
		(layer "F.Cu")
		(net "M_B_CPU1_SA_CS_N<1>")
	)
	(segment
		(start 66.255392 -263.307576)
		(end 65.982342 -263.307576)
		(width 0.18288)
		(layer "In2.Cu")
		(net "M_B_CPU1_SA_CS_N<1>")
	)
	(segment
		(start 65.165478 -262.808974)
		(end 64.865758 -262.808974)
		(width 0.18288)
		(layer "In2.Cu")
		(net "M_B_CPU1_SA_CS_N<1>")
	)
	(segment
		(start 51.246024 -266.591542)
		(end 50.507646 -266.591542)
		(width 0.18288)
		(layer "In2.Cu")
		(net "M_B_CPU1_SA_CS_N<1>")
	)
	(segment
		(start 63.890906 -263.500108)
		(end 63.378334 -263.500108)
		(width 0.18288)
		(layer "In2.Cu")
		(net "M_B_CPU1_SA_CS_N<1>")
	)
	(segment
		(start 46.061884 -267.30706)
		(end 45.901864 -267.46708)
		(width 0.18288)
		(layer "In2.Cu")
		(net "M_B_CPU1_SA_CS_N<1>")
	)
	(segment
		(start 57.694068 -264.509504)
		(end 57.376568 -264.509504)
		(width 0.18288)
		(layer "In2.Cu")
		(net "M_B_CPU1_SA_CS_N<1>")
	)
	(segment
		(start 62.66815 -264.088372)
		(end 61.366908 -264.088372)
		(width 0.18288)
		(layer "In2.Cu")
		(net "M_B_CPU1_SA_CS_N<1>")
	)
	(segment
		(start 66.672968 -262.748014)
		(end 66.672968 -262.89)
		(width 0.18288)
		(layer "In2.Cu")
		(net "M_B_CPU1_SA_CS_N<1>")
	)
	(segment
		(start 56.228488 -264.946892)
		(end 54.6227 -266.55268)
		(width 0.18288)
		(layer "In2.Cu")
		(net "M_B_CPU1_SA_CS_N<1>")
	)
	(segment
		(start 88.56853 -256.09042)
		(end 88.479376 -256.066544)
		(width 0.088646)
		(layer "In2.Cu")
		(net "M_B_CPU1_SA_CS_N<1>")
	)
	(segment
		(start 50.507646 -266.591542)
		(end 50.168048 -266.251944)
		(width 0.18288)
		(layer "In2.Cu")
		(net "M_B_CPU1_SA_CS_N<1>")
	)
	(segment
		(start 48.113696 -265.960606)
		(end 47.834296 -265.960606)
		(width 0.18288)
		(layer "In2.Cu")
		(net "M_B_CPU1_SA_CS_N<1>")
	)
	(segment
		(start 49.441862 -266.251944)
		(end 48.855122 -266.838684)
		(width 0.18288)
		(layer "In2.Cu")
		(net "M_B_CPU1_SA_CS_N<1>")
	)
	(segment
		(start 44.884594 -266.560046)
		(end 44.691554 -266.367006)
		(width 0.18288)
		(layer "In2.Cu")
		(net "M_B_CPU1_SA_CS_N<1>")
	)
	(segment
		(start 45.214794 -265.152378)
		(end 44.878498 -264.816082)
		(width 0.18288)
		(layer "In2.Cu")
		(net "M_B_CPU1_SA_CS_N<1>")
	)
	(segment
		(start 43.964098 -266.823698)
		(end 43.771058 -267.016738)
		(width 0.18288)
		(layer "In2.Cu")
		(net "M_B_CPU1_SA_CS_N<1>")
	)
	(segment
		(start 64.865758 -262.808974)
		(end 64.461898 -263.212834)
		(width 0.18288)
		(layer "In2.Cu")
		(net "M_B_CPU1_SA_CS_N<1>")
	)
	(segment
		(start 45.901864 -267.46708)
		(end 45.423582 -267.46708)
		(width 0.18288)
		(layer "In2.Cu")
		(net "M_B_CPU1_SA_CS_N<1>")
	)
	(segment
		(start 60.955682 -263.677146)
		(end 60.638182 -263.677146)
		(width 0.18288)
		(layer "In2.Cu")
		(net "M_B_CPU1_SA_CS_N<1>")
	)
	(segment
		(start 45.423582 -267.46708)
		(end 45.256958 -267.300456)
		(width 0.18288)
		(layer "In2.Cu")
		(net "M_B_CPU1_SA_CS_N<1>")
	)
	(segment
		(start 80.645762 -258.315206)
		(end 75.02017 -258.315206)
		(width 0.18288)
		(layer "In2.Cu")
		(net "M_B_CPU1_SA_CS_N<1>")
	)
	(segment
		(start 44.878498 -264.816082)
		(end 44.328588 -264.816082)
		(width 0.18288)
		(layer "In2.Cu")
		(net "M_B_CPU1_SA_CS_N<1>")
	)
	(segment
		(start 82.848196 -256.112772)
		(end 80.645762 -258.315206)
		(width 0.18288)
		(layer "In2.Cu")
		(net "M_B_CPU1_SA_CS_N<1>")
	)
	(segment
		(start 65.569338 -263.212834)
		(end 65.165478 -262.808974)
		(width 0.18288)
		(layer "In2.Cu")
		(net "M_B_CPU1_SA_CS_N<1>")
	)
	(segment
		(start 48.855122 -266.838684)
		(end 48.499776 -266.838684)
		(width 0.18288)
		(layer "In2.Cu")
		(net "M_B_CPU1_SA_CS_N<1>")
	)
	(segment
		(start 63.378334 -263.500108)
		(end 63.170054 -263.586468)
		(width 0.18288)
		(layer "In2.Cu")
		(net "M_B_CPU1_SA_CS_N<1>")
	)
	(segment
		(start 48.306736 -266.153646)
		(end 48.113696 -265.960606)
		(width 0.18288)
		(layer "In2.Cu")
		(net "M_B_CPU1_SA_CS_N<1>")
	)
	(segment
		(start 45.256958 -267.300456)
		(end 45.256958 -266.753086)
		(width 0.18288)
		(layer "In2.Cu")
		(net "M_B_CPU1_SA_CS_N<1>")
	)
	(segment
		(start 84.495894 -256.112772)
		(end 83.876134 -256.112772)
		(width 0.088646)
		(layer "In2.Cu")
		(net "M_B_CPU1_SA_CS_N<1>")
	)
	(segment
		(start 58.131456 -264.946892)
		(end 57.694068 -264.509504)
		(width 0.18288)
		(layer "In2.Cu")
		(net "M_B_CPU1_SA_CS_N<1>")
	)
	(segment
		(start 64.461898 -263.212834)
		(end 64.17818 -263.212834)
		(width 0.18288)
		(layer "In2.Cu")
		(net "M_B_CPU1_SA_CS_N<1>")
	)
	(segment
		(start 47.410116 -266.591796)
		(end 46.225206 -266.591796)
		(width 0.18288)
		(layer "In2.Cu")
		(net "M_B_CPU1_SA_CS_N<1>")
	)
	(segment
		(start 44.691554 -266.367006)
		(end 44.691554 -266.03833)
		(width 0.18288)
		(layer "In2.Cu")
		(net "M_B_CPU1_SA_CS_N<1>")
	)
	(segment
		(start 56.93918 -264.946892)
		(end 56.228488 -264.946892)
		(width 0.18288)
		(layer "In2.Cu")
		(net "M_B_CPU1_SA_CS_N<1>")
	)
	(segment
		(start 63.170054 -263.586468)
		(end 62.66815 -264.088372)
		(width 0.18288)
		(layer "In2.Cu")
		(net "M_B_CPU1_SA_CS_N<1>")
	)
	(segment
		(start 43.964098 -265.180572)
		(end 43.964098 -266.823698)
		(width 0.18288)
		(layer "In2.Cu")
		(net "M_B_CPU1_SA_CS_N<1>")
	)
	(segment
		(start 45.256958 -266.753086)
		(end 45.063918 -266.560046)
		(width 0.18288)
		(layer "In2.Cu")
		(net "M_B_CPU1_SA_CS_N<1>")
	)
	(segment
		(start 60.226956 -264.088372)
		(end 59.468258 -264.088372)
		(width 0.18288)
		(layer "In2.Cu")
		(net "M_B_CPU1_SA_CS_N<1>")
	)
	(segment
		(start 44.328588 -264.816082)
		(end 43.964098 -265.180572)
		(width 0.18288)
		(layer "In2.Cu")
		(net "M_B_CPU1_SA_CS_N<1>")
	)
	(segment
		(start 88.724994 -256.361438)
		(end 88.56853 -256.09042)
		(width 0.088646)
		(layer "In2.Cu")
		(net "M_B_CPU1_SA_CS_N<1>")
	)
	(segment
		(start 45.214794 -265.51509)
		(end 45.214794 -265.152378)
		(width 0.18288)
		(layer "In2.Cu")
		(net "M_B_CPU1_SA_CS_N<1>")
	)
	(segment
		(start 47.834296 -265.960606)
		(end 47.603156 -266.191746)
		(width 0.18288)
		(layer "In2.Cu")
		(net "M_B_CPU1_SA_CS_N<1>")
	)
	(segment
		(start 83.876134 -256.112772)
		(end 82.848196 -256.112772)
		(width 0.18288)
		(layer "In2.Cu")
		(net "M_B_CPU1_SA_CS_N<1>")
	)
	(segment
		(start 75.02017 -258.315206)
		(end 74.403458 -258.931918)
		(width 0.18288)
		(layer "In2.Cu")
		(net "M_B_CPU1_SA_CS_N<1>")
	)
	(segment
		(start 48.499776 -266.838684)
		(end 48.306736 -266.645644)
		(width 0.18288)
		(layer "In2.Cu")
		(net "M_B_CPU1_SA_CS_N<1>")
	)
	(segment
		(start 60.638182 -263.677146)
		(end 60.226956 -264.088372)
		(width 0.18288)
		(layer "In2.Cu")
		(net "M_B_CPU1_SA_CS_N<1>")
	)
	(segment
		(start 59.468258 -264.088372)
		(end 59.124088 -264.432542)
		(width 0.18288)
		(layer "In2.Cu")
		(net "M_B_CPU1_SA_CS_N<1>")
	)
	(segment
		(start 50.168048 -266.251944)
		(end 49.441862 -266.251944)
		(width 0.18288)
		(layer "In2.Cu")
		(net "M_B_CPU1_SA_CS_N<1>")
	)
	(segment
		(start 46.061884 -266.755118)
		(end 46.061884 -267.30706)
		(width 0.18288)
		(layer "In2.Cu")
		(net "M_B_CPU1_SA_CS_N<1>")
	)
	(segment
		(start 65.982342 -263.307576)
		(end 65.8876 -263.212834)
		(width 0.18288)
		(layer "In2.Cu")
		(net "M_B_CPU1_SA_CS_N<1>")
	)
	(segment
		(start 74.403458 -258.931918)
		(end 67.718432 -261.70255)
		(width 0.18288)
		(layer "In2.Cu")
		(net "M_B_CPU1_SA_CS_N<1>")
	)
	(segment
		(start 54.6227 -266.55268)
		(end 52.50942 -266.55268)
		(width 0.18288)
		(layer "In2.Cu")
		(net "M_B_CPU1_SA_CS_N<1>")
	)
	(segment
		(start 65.8876 -263.212834)
		(end 65.569338 -263.212834)
		(width 0.18288)
		(layer "In2.Cu")
		(net "M_B_CPU1_SA_CS_N<1>")
	)
	(segment
		(start 59.124088 -264.567162)
		(end 58.744358 -264.946892)
		(width 0.18288)
		(layer "In2.Cu")
		(net "M_B_CPU1_SA_CS_N<1>")
	)
	(segment
		(start 44.691554 -266.03833)
		(end 45.214794 -265.51509)
		(width 0.18288)
		(layer "In2.Cu")
		(net "M_B_CPU1_SA_CS_N<1>")
	)
	(segment
		(start 47.603156 -266.398756)
		(end 47.410116 -266.591796)
		(width 0.18288)
		(layer "In2.Cu")
		(net "M_B_CPU1_SA_CS_N<1>")
	)
	(segment
		(start 61.366908 -264.088372)
		(end 60.955682 -263.677146)
		(width 0.18288)
		(layer "In2.Cu")
		(net "M_B_CPU1_SA_CS_N<1>")
	)
	(segment
		(start 59.124088 -264.432542)
		(end 59.124088 -264.567162)
		(width 0.18288)
		(layer "In2.Cu")
		(net "M_B_CPU1_SA_CS_N<1>")
	)
	(segment
		(start 66.672968 -262.89)
		(end 66.255392 -263.307576)
		(width 0.18288)
		(layer "In2.Cu")
		(net "M_B_CPU1_SA_CS_N<1>")
	)
	(segment
		(start 58.744358 -264.946892)
		(end 58.131456 -264.946892)
		(width 0.18288)
		(layer "In2.Cu")
		(net "M_B_CPU1_SA_CS_N<1>")
	)
	(segment
		(start 57.376568 -264.509504)
		(end 56.93918 -264.946892)
		(width 0.18288)
		(layer "In2.Cu")
		(net "M_B_CPU1_SA_CS_N<1>")
	)
	(segment
		(start 48.306736 -266.645644)
		(end 48.306736 -266.153646)
		(width 0.18288)
		(layer "In2.Cu")
		(net "M_B_CPU1_SA_CS_N<1>")
	)
	(segment
		(start 52.50942 -266.55268)
		(end 52.2605 -266.30376)
		(width 0.18288)
		(layer "In2.Cu")
		(net "M_B_CPU1_SA_CS_N<1>")
	)
	(segment
		(start 52.2605 -266.30376)
		(end 51.533806 -266.30376)
		(width 0.18288)
		(layer "In2.Cu")
		(net "M_B_CPU1_SA_CS_N<1>")
	)
	(segment
		(start 46.225206 -266.591796)
		(end 46.061884 -266.755118)
		(width 0.18288)
		(layer "In2.Cu")
		(net "M_B_CPU1_SA_CS_N<1>")
	)
	(segment
		(start 47.603156 -266.191746)
		(end 47.603156 -266.398756)
		(width 0.18288)
		(layer "In2.Cu")
		(net "M_B_CPU1_SA_CS_N<1>")
	)
	(segment
		(start 43.771058 -267.016738)
		(end 43.520614 -267.016738)
		(width 0.18288)
		(layer "In2.Cu")
		(net "M_B_CPU1_SA_CS_N<1>")
	)
	(segment
		(start 64.17818 -263.212834)
		(end 63.890906 -263.500108)
		(width 0.18288)
		(layer "In2.Cu")
		(net "M_B_CPU1_SA_CS_N<1>")
	)
	(segment
		(start 51.533806 -266.30376)
		(end 51.246024 -266.591542)
		(width 0.18288)
		(layer "In2.Cu")
		(net "M_B_CPU1_SA_CS_N<1>")
	)
	(segment
		(start 67.718432 -261.70255)
		(end 66.672968 -262.748014)
		(width 0.18288)
		(layer "In2.Cu")
		(net "M_B_CPU1_SA_CS_N<1>")
	)
	(segment
		(start 45.063918 -266.560046)
		(end 44.884594 -266.560046)
		(width 0.18288)
		(layer "In2.Cu")
		(net "M_B_CPU1_SA_CS_N<1>")
	)
	(arc
		(start 86.092792 -256.03708)
		(mid 85.905594 -255.986937)
		(end 85.718396 -256.03708)
		(width 0.088646)
		(layer "In2.Cu")
		(net "M_B_CPU1_SA_CS_N<1>")
	)
	(arc
		(start 87.972392 -256.03708)
		(mid 87.785194 -255.986937)
		(end 87.597996 -256.03708)
		(width 0.088646)
		(layer "In2.Cu")
		(net "M_B_CPU1_SA_CS_N<1>")
	)
	(arc
		(start 84.778596 -256.03708)
		(mid 84.642227 -256.093522)
		(end 84.495894 -256.112772)
		(width 0.088646)
		(layer "In2.Cu")
		(net "M_B_CPU1_SA_CS_N<1>")
	)
	(arc
		(start 87.597996 -256.03708)
		(mid 87.315294 -256.112856)
		(end 87.032592 -256.03708)
		(width 0.088646)
		(layer "In2.Cu")
		(net "M_B_CPU1_SA_CS_N<1>")
	)
	(arc
		(start 85.718396 -256.03708)
		(mid 85.435694 -256.112856)
		(end 85.152992 -256.03708)
		(width 0.088646)
		(layer "In2.Cu")
		(net "M_B_CPU1_SA_CS_N<1>")
	)
	(arc
		(start 87.032592 -256.03708)
		(mid 86.845394 -255.986937)
		(end 86.658196 -256.03708)
		(width 0.088646)
		(layer "In2.Cu")
		(net "M_B_CPU1_SA_CS_N<1>")
	)
	(arc
		(start 85.152992 -256.03708)
		(mid 84.965794 -255.986937)
		(end 84.778596 -256.03708)
		(width 0.088646)
		(layer "In2.Cu")
		(net "M_B_CPU1_SA_CS_N<1>")
	)
	(arc
		(start 86.658196 -256.03708)
		(mid 86.375494 -256.112856)
		(end 86.092792 -256.03708)
		(width 0.088646)
		(layer "In2.Cu")
		(net "M_B_CPU1_SA_CS_N<1>")
	)
	(arc
		(start 88.479376 -256.066544)
		(mid 88.222377 -256.111991)
		(end 87.972392 -256.03708)
		(width 0.088646)
		(layer "In2.Cu")
		(net "M_B_CPU1_SA_CS_N<1>")
	)
	(segment
		(start 89.194894 -257.175254)
		(end 89.194894 -256.639314)
		(width 0.20066)
		(layer "F.Cu")
		(net "M_B_CPU1_SA_CS_N<0>")
	)
	(segment
		(start 38.315646 -267.866622)
		(end 39.420546 -267.866622)
		(width 0.20066)
		(layer "F.Cu")
		(net "M_B_CPU1_SA_CS_N<0>")
	)
	(segment
		(start 83.901788 -257.182366)
		(end 83.62315 -257.182366)
		(width 0.088646)
		(layer "In2.Cu")
		(net "M_B_CPU1_SA_CS_N<0>")
	)
	(segment
		(start 41.10482 -268.298676)
		(end 40.9448 -268.458696)
		(width 0.18288)
		(layer "In2.Cu")
		(net "M_B_CPU1_SA_CS_N<0>")
	)
	(segment
		(start 40.75176 -269.01648)
		(end 40.337486 -269.01648)
		(width 0.18288)
		(layer "In2.Cu")
		(net "M_B_CPU1_SA_CS_N<0>")
	)
	(segment
		(start 39.8526 -268.298676)
		(end 39.420546 -267.866622)
		(width 0.18288)
		(layer "In2.Cu")
		(net "M_B_CPU1_SA_CS_N<0>")
	)
	(segment
		(start 40.9448 -268.82344)
		(end 40.75176 -269.01648)
		(width 0.18288)
		(layer "In2.Cu")
		(net "M_B_CPU1_SA_CS_N<0>")
	)
	(segment
		(start 75.218798 -260.273038)
		(end 69.168772 -262.779256)
		(width 0.18288)
		(layer "In2.Cu")
		(net "M_B_CPU1_SA_CS_N<0>")
	)
	(segment
		(start 48.345852 -268.46784)
		(end 47.681388 -268.46784)
		(width 0.18288)
		(layer "In2.Cu")
		(net "M_B_CPU1_SA_CS_N<0>")
	)
	(segment
		(start 88.470232 -257.483356)
		(end 88.442292 -257.499612)
		(width 0.088646)
		(layer "In2.Cu")
		(net "M_B_CPU1_SA_CS_N<0>")
	)
	(segment
		(start 76.14031 -259.351526)
		(end 75.218798 -260.273038)
		(width 0.18288)
		(layer "In2.Cu")
		(net "M_B_CPU1_SA_CS_N<0>")
	)
	(segment
		(start 63.980314 -265.688826)
		(end 61.845952 -266.572746)
		(width 0.18288)
		(layer "In2.Cu")
		(net "M_B_CPU1_SA_CS_N<0>")
	)
	(segment
		(start 44.029376 -268.298676)
		(end 41.10482 -268.298676)
		(width 0.18288)
		(layer "In2.Cu")
		(net "M_B_CPU1_SA_CS_N<0>")
	)
	(segment
		(start 56.248554 -267.411708)
		(end 55.590186 -268.070076)
		(width 0.18288)
		(layer "In2.Cu")
		(net "M_B_CPU1_SA_CS_N<0>")
	)
	(segment
		(start 45.33773 -268.556232)
		(end 44.953174 -268.171676)
		(width 0.18288)
		(layer "In2.Cu")
		(net "M_B_CPU1_SA_CS_N<0>")
	)
	(segment
		(start 39.984426 -268.298676)
		(end 39.8526 -268.298676)
		(width 0.18288)
		(layer "In2.Cu")
		(net "M_B_CPU1_SA_CS_N<0>")
	)
	(segment
		(start 40.9448 -268.458696)
		(end 40.9448 -268.82344)
		(width 0.18288)
		(layer "In2.Cu")
		(net "M_B_CPU1_SA_CS_N<0>")
	)
	(segment
		(start 84.26958 -257.550158)
		(end 83.901788 -257.182366)
		(width 0.088646)
		(layer "In2.Cu")
		(net "M_B_CPU1_SA_CS_N<0>")
	)
	(segment
		(start 83.24469 -257.182366)
		(end 81.07553 -259.351526)
		(width 0.18288)
		(layer "In2.Cu")
		(net "M_B_CPU1_SA_CS_N<0>")
	)
	(segment
		(start 83.62315 -257.182366)
		(end 83.24469 -257.182366)
		(width 0.18288)
		(layer "In2.Cu")
		(net "M_B_CPU1_SA_CS_N<0>")
	)
	(segment
		(start 69.168772 -262.779256)
		(end 66.259202 -265.688826)
		(width 0.18288)
		(layer "In2.Cu")
		(net "M_B_CPU1_SA_CS_N<0>")
	)
	(segment
		(start 52.11953 -269.14348)
		(end 51.274726 -268.298676)
		(width 0.18288)
		(layer "In2.Cu")
		(net "M_B_CPU1_SA_CS_N<0>")
	)
	(segment
		(start 54.71287 -269.14348)
		(end 52.11953 -269.14348)
		(width 0.18288)
		(layer "In2.Cu")
		(net "M_B_CPU1_SA_CS_N<0>")
	)
	(segment
		(start 51.274726 -268.298676)
		(end 48.515016 -268.298676)
		(width 0.18288)
		(layer "In2.Cu")
		(net "M_B_CPU1_SA_CS_N<0>")
	)
	(segment
		(start 47.681388 -268.46784)
		(end 47.505366 -268.291818)
		(width 0.18288)
		(layer "In2.Cu")
		(net "M_B_CPU1_SA_CS_N<0>")
	)
	(segment
		(start 44.156376 -268.171676)
		(end 44.029376 -268.298676)
		(width 0.18288)
		(layer "In2.Cu")
		(net "M_B_CPU1_SA_CS_N<0>")
	)
	(segment
		(start 40.337486 -269.01648)
		(end 40.144446 -268.82344)
		(width 0.18288)
		(layer "In2.Cu")
		(net "M_B_CPU1_SA_CS_N<0>")
	)
	(segment
		(start 46.439074 -268.556232)
		(end 45.33773 -268.556232)
		(width 0.18288)
		(layer "In2.Cu")
		(net "M_B_CPU1_SA_CS_N<0>")
	)
	(segment
		(start 55.590186 -268.266164)
		(end 54.71287 -269.14348)
		(width 0.18288)
		(layer "In2.Cu")
		(net "M_B_CPU1_SA_CS_N<0>")
	)
	(segment
		(start 47.505366 -268.291818)
		(end 46.703488 -268.291818)
		(width 0.18288)
		(layer "In2.Cu")
		(net "M_B_CPU1_SA_CS_N<0>")
	)
	(segment
		(start 66.259202 -265.688826)
		(end 63.980314 -265.688826)
		(width 0.18288)
		(layer "In2.Cu")
		(net "M_B_CPU1_SA_CS_N<0>")
	)
	(segment
		(start 84.495894 -257.550158)
		(end 84.26958 -257.550158)
		(width 0.088646)
		(layer "In2.Cu")
		(net "M_B_CPU1_SA_CS_N<0>")
	)
	(segment
		(start 40.144446 -268.458696)
		(end 39.984426 -268.298676)
		(width 0.18288)
		(layer "In2.Cu")
		(net "M_B_CPU1_SA_CS_N<0>")
	)
	(segment
		(start 58.771282 -267.411708)
		(end 56.248554 -267.411708)
		(width 0.18288)
		(layer "In2.Cu")
		(net "M_B_CPU1_SA_CS_N<0>")
	)
	(segment
		(start 44.953174 -268.171676)
		(end 44.156376 -268.171676)
		(width 0.18288)
		(layer "In2.Cu")
		(net "M_B_CPU1_SA_CS_N<0>")
	)
	(segment
		(start 89.194894 -257.175254)
		(end 88.470232 -257.483356)
		(width 0.088646)
		(layer "In2.Cu")
		(net "M_B_CPU1_SA_CS_N<0>")
	)
	(segment
		(start 40.144446 -268.82344)
		(end 40.144446 -268.458696)
		(width 0.18288)
		(layer "In2.Cu")
		(net "M_B_CPU1_SA_CS_N<0>")
	)
	(segment
		(start 55.590186 -268.070076)
		(end 55.590186 -268.266164)
		(width 0.18288)
		(layer "In2.Cu")
		(net "M_B_CPU1_SA_CS_N<0>")
	)
	(segment
		(start 46.703488 -268.291818)
		(end 46.439074 -268.556232)
		(width 0.18288)
		(layer "In2.Cu")
		(net "M_B_CPU1_SA_CS_N<0>")
	)
	(segment
		(start 59.610244 -266.572746)
		(end 58.771282 -267.411708)
		(width 0.18288)
		(layer "In2.Cu")
		(net "M_B_CPU1_SA_CS_N<0>")
	)
	(segment
		(start 81.07553 -259.351526)
		(end 76.14031 -259.351526)
		(width 0.18288)
		(layer "In2.Cu")
		(net "M_B_CPU1_SA_CS_N<0>")
	)
	(segment
		(start 48.515016 -268.298676)
		(end 48.345852 -268.46784)
		(width 0.18288)
		(layer "In2.Cu")
		(net "M_B_CPU1_SA_CS_N<0>")
	)
	(segment
		(start 61.845952 -266.572746)
		(end 59.610244 -266.572746)
		(width 0.18288)
		(layer "In2.Cu")
		(net "M_B_CPU1_SA_CS_N<0>")
	)
	(arc
		(start 85.248496 -257.499612)
		(mid 84.965794 -257.423836)
		(end 84.683092 -257.499612)
		(width 0.088646)
		(layer "In2.Cu")
		(net "M_B_CPU1_SA_CS_N<0>")
	)
	(arc
		(start 87.502492 -257.499612)
		(mid 87.315294 -257.549755)
		(end 87.128096 -257.499612)
		(width 0.088646)
		(layer "In2.Cu")
		(net "M_B_CPU1_SA_CS_N<0>")
	)
	(arc
		(start 86.562692 -257.499612)
		(mid 86.375494 -257.549755)
		(end 86.188296 -257.499612)
		(width 0.088646)
		(layer "In2.Cu")
		(net "M_B_CPU1_SA_CS_N<0>")
	)
	(arc
		(start 88.442292 -257.499612)
		(mid 88.255094 -257.549755)
		(end 88.067896 -257.499612)
		(width 0.088646)
		(layer "In2.Cu")
		(net "M_B_CPU1_SA_CS_N<0>")
	)
	(arc
		(start 88.067896 -257.499612)
		(mid 87.785194 -257.423836)
		(end 87.502492 -257.499612)
		(width 0.088646)
		(layer "In2.Cu")
		(net "M_B_CPU1_SA_CS_N<0>")
	)
	(arc
		(start 87.128096 -257.499612)
		(mid 86.845394 -257.42387)
		(end 86.562692 -257.499612)
		(width 0.088646)
		(layer "In2.Cu")
		(net "M_B_CPU1_SA_CS_N<0>")
	)
	(arc
		(start 85.622892 -257.499612)
		(mid 85.435694 -257.549755)
		(end 85.248496 -257.499612)
		(width 0.088646)
		(layer "In2.Cu")
		(net "M_B_CPU1_SA_CS_N<0>")
	)
	(arc
		(start 84.683092 -257.499612)
		(mid 84.59282 -257.537211)
		(end 84.495894 -257.550158)
		(width 0.088646)
		(layer "In2.Cu")
		(net "M_B_CPU1_SA_CS_N<0>")
	)
	(arc
		(start 86.188296 -257.499612)
		(mid 85.905594 -257.423836)
		(end 85.622892 -257.499612)
		(width 0.088646)
		(layer "In2.Cu")
		(net "M_B_CPU1_SA_CS_N<0>")
	)
	(segment
		(start 44.238926 -270.542766)
		(end 44.112942 -270.416782)
		(width 0.20066)
		(layer "F.Cu")
		(net "M_B_CPU1_SA_CB<7>")
	)
	(segment
		(start 48.489362 -270.6243)
		(end 48.277526 -270.412464)
		(width 0.20066)
		(layer "F.Cu")
		(net "M_B_CPU1_SA_CB<7>")
	)
	(segment
		(start 47.60468 -270.841724)
		(end 47.060358 -270.841724)
		(width 0.20066)
		(layer "F.Cu")
		(net "M_B_CPU1_SA_CB<7>")
	)
	(segment
		(start 44.238926 -270.713454)
		(end 44.238926 -270.542766)
		(width 0.20066)
		(layer "F.Cu")
		(net "M_B_CPU1_SA_CB<7>")
	)
	(segment
		(start 48.277526 -270.412464)
		(end 47.882302 -270.412464)
		(width 0.20066)
		(layer "F.Cu")
		(net "M_B_CPU1_SA_CB<7>")
	)
	(segment
		(start 47.882302 -270.412464)
		(end 47.753778 -270.540988)
		(width 0.20066)
		(layer "F.Cu")
		(net "M_B_CPU1_SA_CB<7>")
	)
	(segment
		(start 49.959514 -270.416782)
		(end 49.143412 -270.416782)
		(width 0.20066)
		(layer "F.Cu")
		(net "M_B_CPU1_SA_CB<7>")
	)
	(segment
		(start 51.089814 -270.416782)
		(end 49.959514 -270.416782)
		(width 0.20066)
		(layer "F.Cu")
		(net "M_B_CPU1_SA_CB<7>")
	)
	(segment
		(start 44.987464 -270.841724)
		(end 44.749466 -270.841724)
		(width 0.101854)
		(layer "F.Cu")
		(net "M_B_CPU1_SA_CB<7>")
	)
	(segment
		(start 47.060358 -270.841724)
		(end 44.987464 -270.841724)
		(width 0.1016)
		(layer "F.Cu")
		(net "M_B_CPU1_SA_CB<7>")
	)
	(segment
		(start 48.935894 -270.6243)
		(end 48.489362 -270.6243)
		(width 0.20066)
		(layer "F.Cu")
		(net "M_B_CPU1_SA_CB<7>")
	)
	(segment
		(start 44.735242 -270.855948)
		(end 44.38142 -270.855948)
		(width 0.20066)
		(layer "F.Cu")
		(net "M_B_CPU1_SA_CB<7>")
	)
	(segment
		(start 44.749466 -270.841724)
		(end 44.735242 -270.855948)
		(width 0.101854)
		(layer "F.Cu")
		(net "M_B_CPU1_SA_CB<7>")
	)
	(segment
		(start 47.753778 -270.540988)
		(end 47.753778 -270.692626)
		(width 0.20066)
		(layer "F.Cu")
		(net "M_B_CPU1_SA_CB<7>")
	)
	(segment
		(start 44.112942 -270.416782)
		(end 42.415714 -270.416782)
		(width 0.20066)
		(layer "F.Cu")
		(net "M_B_CPU1_SA_CB<7>")
	)
	(segment
		(start 44.38142 -270.855948)
		(end 44.238926 -270.713454)
		(width 0.20066)
		(layer "F.Cu")
		(net "M_B_CPU1_SA_CB<7>")
	)
	(segment
		(start 49.143412 -270.416782)
		(end 48.935894 -270.6243)
		(width 0.20066)
		(layer "F.Cu")
		(net "M_B_CPU1_SA_CB<7>")
	)
	(segment
		(start 90.134694 -258.2672)
		(end 90.134694 -258.80314)
		(width 0.20066)
		(layer "F.Cu")
		(net "M_B_CPU1_SA_CB<7>")
	)
	(segment
		(start 47.753778 -270.692626)
		(end 47.60468 -270.841724)
		(width 0.20066)
		(layer "F.Cu")
		(net "M_B_CPU1_SA_CB<7>")
	)
	(segment
		(start 67.568572 -267.295884)
		(end 66.991992 -267.295884)
		(width 0.18288)
		(layer "In2.Cu")
		(net "M_B_CPU1_SA_CB<7>")
	)
	(segment
		(start 68.695316 -266.16914)
		(end 68.42252 -266.16914)
		(width 0.18288)
		(layer "In2.Cu")
		(net "M_B_CPU1_SA_CB<7>")
	)
	(segment
		(start 67.924934 -266.939522)
		(end 67.568572 -267.295884)
		(width 0.18288)
		(layer "In2.Cu")
		(net "M_B_CPU1_SA_CB<7>")
	)
	(segment
		(start 70.412864 -264.178796)
		(end 70.282562 -264.048494)
		(width 0.18288)
		(layer "In2.Cu")
		(net "M_B_CPU1_SA_CB<7>")
	)
	(segment
		(start 90.134694 -258.80314)
		(end 89.821766 -258.80314)
		(width 0.088646)
		(layer "In2.Cu")
		(net "M_B_CPU1_SA_CB<7>")
	)
	(segment
		(start 65.54851 -268.291818)
		(end 65.35547 -268.098778)
		(width 0.18288)
		(layer "In2.Cu")
		(net "M_B_CPU1_SA_CB<7>")
	)
	(segment
		(start 66.500756 -268.291818)
		(end 65.54851 -268.291818)
		(width 0.18288)
		(layer "In2.Cu")
		(net "M_B_CPU1_SA_CB<7>")
	)
	(segment
		(start 64.65189 -267.63726)
		(end 64.65189 -268.098778)
		(width 0.18288)
		(layer "In2.Cu")
		(net "M_B_CPU1_SA_CB<7>")
	)
	(segment
		(start 68.292218 -266.038838)
		(end 68.019422 -266.038838)
		(width 0.18288)
		(layer "In2.Cu")
		(net "M_B_CPU1_SA_CB<7>")
	)
	(segment
		(start 81.550256 -260.652006)
		(end 76.909422 -260.652006)
		(width 0.18288)
		(layer "In2.Cu")
		(net "M_B_CPU1_SA_CB<7>")
	)
	(segment
		(start 65.35547 -267.6398)
		(end 65.15989 -267.44422)
		(width 0.18288)
		(layer "In2.Cu")
		(net "M_B_CPU1_SA_CB<7>")
	)
	(segment
		(start 83.933284 -258.534154)
		(end 83.824826 -258.534154)
		(width 0.088646)
		(layer "In2.Cu")
		(net "M_B_CPU1_SA_CB<7>")
	)
	(segment
		(start 69.784976 -264.273284)
		(end 69.784976 -264.54608)
		(width 0.18288)
		(layer "In2.Cu")
		(net "M_B_CPU1_SA_CB<7>")
	)
	(segment
		(start 69.915278 -264.676382)
		(end 69.915278 -264.949178)
		(width 0.18288)
		(layer "In2.Cu")
		(net "M_B_CPU1_SA_CB<7>")
	)
	(segment
		(start 56.00446 -269.993364)
		(end 55.734712 -270.263112)
		(width 0.18288)
		(layer "In2.Cu")
		(net "M_B_CPU1_SA_CB<7>")
	)
	(segment
		(start 70.009766 -264.048494)
		(end 69.784976 -264.273284)
		(width 0.18288)
		(layer "In2.Cu")
		(net "M_B_CPU1_SA_CB<7>")
	)
	(segment
		(start 66.751708 -267.536168)
		(end 66.751708 -268.040866)
		(width 0.18288)
		(layer "In2.Cu")
		(net "M_B_CPU1_SA_CB<7>")
	)
	(segment
		(start 61.470032 -269.141702)
		(end 61.276992 -268.948662)
		(width 0.18288)
		(layer "In2.Cu")
		(net "M_B_CPU1_SA_CB<7>")
	)
	(segment
		(start 69.915278 -264.949178)
		(end 69.690488 -265.173968)
		(width 0.18288)
		(layer "In2.Cu")
		(net "M_B_CPU1_SA_CB<7>")
	)
	(segment
		(start 57.280556 -269.2654)
		(end 57.087516 -269.45844)
		(width 0.18288)
		(layer "In2.Cu")
		(net "M_B_CPU1_SA_CB<7>")
	)
	(segment
		(start 60.774072 -268.2748)
		(end 60.573412 -268.47546)
		(width 0.18288)
		(layer "In2.Cu")
		(net "M_B_CPU1_SA_CB<7>")
	)
	(segment
		(start 64.238378 -268.309852)
		(end 63.922148 -268.440916)
		(width 0.18288)
		(layer "In2.Cu")
		(net "M_B_CPU1_SA_CB<7>")
	)
	(segment
		(start 64.84493 -267.44422)
		(end 64.65189 -267.63726)
		(width 0.18288)
		(layer "In2.Cu")
		(net "M_B_CPU1_SA_CB<7>")
	)
	(segment
		(start 55.734712 -270.263112)
		(end 55.734712 -270.53032)
		(width 0.18288)
		(layer "In2.Cu")
		(net "M_B_CPU1_SA_CB<7>")
	)
	(segment
		(start 55.734712 -270.53032)
		(end 55.369206 -270.895826)
		(width 0.18288)
		(layer "In2.Cu")
		(net "M_B_CPU1_SA_CB<7>")
	)
	(segment
		(start 66.991992 -267.295884)
		(end 66.751708 -267.536168)
		(width 0.18288)
		(layer "In2.Cu")
		(net "M_B_CPU1_SA_CB<7>")
	)
	(segment
		(start 64.45885 -268.291818)
		(end 64.256412 -268.291818)
		(width 0.18288)
		(layer "In2.Cu")
		(net "M_B_CPU1_SA_CB<7>")
	)
	(segment
		(start 61.276992 -268.948662)
		(end 61.276992 -268.46784)
		(width 0.18288)
		(layer "In2.Cu")
		(net "M_B_CPU1_SA_CB<7>")
	)
	(segment
		(start 65.15989 -267.44422)
		(end 64.84493 -267.44422)
		(width 0.18288)
		(layer "In2.Cu")
		(net "M_B_CPU1_SA_CB<7>")
	)
	(segment
		(start 57.791096 -269.45844)
		(end 57.598056 -269.2654)
		(width 0.18288)
		(layer "In2.Cu")
		(net "M_B_CPU1_SA_CB<7>")
	)
	(segment
		(start 65.35547 -268.098778)
		(end 65.35547 -267.6398)
		(width 0.18288)
		(layer "In2.Cu")
		(net "M_B_CPU1_SA_CB<7>")
	)
	(segment
		(start 70.282562 -264.048494)
		(end 70.009766 -264.048494)
		(width 0.18288)
		(layer "In2.Cu")
		(net "M_B_CPU1_SA_CB<7>")
	)
	(segment
		(start 63.30188 -267.950696)
		(end 63.008002 -268.072616)
		(width 0.18288)
		(layer "In2.Cu")
		(net "M_B_CPU1_SA_CB<7>")
	)
	(segment
		(start 63.922148 -268.440916)
		(end 63.67018 -268.336268)
		(width 0.18288)
		(layer "In2.Cu")
		(net "M_B_CPU1_SA_CB<7>")
	)
	(segment
		(start 68.920106 -265.94435)
		(end 68.695316 -266.16914)
		(width 0.18288)
		(layer "In2.Cu")
		(net "M_B_CPU1_SA_CB<7>")
	)
	(segment
		(start 59.082178 -269.794228)
		(end 58.883042 -269.993364)
		(width 0.18288)
		(layer "In2.Cu")
		(net "M_B_CPU1_SA_CB<7>")
	)
	(segment
		(start 57.984136 -269.993364)
		(end 57.791096 -269.800324)
		(width 0.18288)
		(layer "In2.Cu")
		(net "M_B_CPU1_SA_CB<7>")
	)
	(segment
		(start 67.794632 -266.536424)
		(end 67.924934 -266.666726)
		(width 0.18288)
		(layer "In2.Cu")
		(net "M_B_CPU1_SA_CB<7>")
	)
	(segment
		(start 89.821766 -258.80314)
		(end 89.756742 -258.738116)
		(width 0.088646)
		(layer "In2.Cu")
		(net "M_B_CPU1_SA_CB<7>")
	)
	(segment
		(start 68.019422 -266.038838)
		(end 67.794632 -266.263628)
		(width 0.18288)
		(layer "In2.Cu")
		(net "M_B_CPU1_SA_CB<7>")
	)
	(segment
		(start 52.26812 -271.147032)
		(end 51.820064 -271.147032)
		(width 0.18288)
		(layer "In2.Cu")
		(net "M_B_CPU1_SA_CB<7>")
	)
	(segment
		(start 51.820064 -271.147032)
		(end 51.089814 -270.416782)
		(width 0.18288)
		(layer "In2.Cu")
		(net "M_B_CPU1_SA_CB<7>")
	)
	(segment
		(start 76.909422 -260.652006)
		(end 75.939396 -261.622032)
		(width 0.18288)
		(layer "In2.Cu")
		(net "M_B_CPU1_SA_CB<7>")
	)
	(segment
		(start 61.083952 -268.2748)
		(end 60.774072 -268.2748)
		(width 0.18288)
		(layer "In2.Cu")
		(net "M_B_CPU1_SA_CB<7>")
	)
	(segment
		(start 69.28739 -265.043666)
		(end 69.014594 -265.043666)
		(width 0.18288)
		(layer "In2.Cu")
		(net "M_B_CPU1_SA_CB<7>")
	)
	(segment
		(start 68.789804 -265.268456)
		(end 68.789804 -265.541252)
		(width 0.18288)
		(layer "In2.Cu")
		(net "M_B_CPU1_SA_CB<7>")
	)
	(segment
		(start 66.751708 -268.040866)
		(end 66.500756 -268.291818)
		(width 0.18288)
		(layer "In2.Cu")
		(net "M_B_CPU1_SA_CB<7>")
	)
	(segment
		(start 62.973458 -268.998192)
		(end 62.626748 -269.141702)
		(width 0.18288)
		(layer "In2.Cu")
		(net "M_B_CPU1_SA_CB<7>")
	)
	(segment
		(start 62.903354 -268.324838)
		(end 63.077852 -268.745716)
		(width 0.18288)
		(layer "In2.Cu")
		(net "M_B_CPU1_SA_CB<7>")
	)
	(segment
		(start 69.014594 -265.043666)
		(end 68.789804 -265.268456)
		(width 0.18288)
		(layer "In2.Cu")
		(net "M_B_CPU1_SA_CB<7>")
	)
	(segment
		(start 59.275218 -269.20571)
		(end 59.082178 -269.39875)
		(width 0.18288)
		(layer "In2.Cu")
		(net "M_B_CPU1_SA_CB<7>")
	)
	(segment
		(start 84.229702 -258.237736)
		(end 83.933284 -258.534154)
		(width 0.088646)
		(layer "In2.Cu")
		(net "M_B_CPU1_SA_CB<7>")
	)
	(segment
		(start 63.553594 -268.055344)
		(end 63.30188 -267.950696)
		(width 0.18288)
		(layer "In2.Cu")
		(net "M_B_CPU1_SA_CB<7>")
	)
	(segment
		(start 70.68566 -264.178796)
		(end 70.412864 -264.178796)
		(width 0.18288)
		(layer "In2.Cu")
		(net "M_B_CPU1_SA_CB<7>")
	)
	(segment
		(start 75.939396 -261.622032)
		(end 71.334884 -263.529572)
		(width 0.18288)
		(layer "In2.Cu")
		(net "M_B_CPU1_SA_CB<7>")
	)
	(segment
		(start 68.42252 -266.16914)
		(end 68.292218 -266.038838)
		(width 0.18288)
		(layer "In2.Cu")
		(net "M_B_CPU1_SA_CB<7>")
	)
	(segment
		(start 57.791096 -269.800324)
		(end 57.791096 -269.45844)
		(width 0.18288)
		(layer "In2.Cu")
		(net "M_B_CPU1_SA_CB<7>")
	)
	(segment
		(start 69.417692 -265.173968)
		(end 69.28739 -265.043666)
		(width 0.18288)
		(layer "In2.Cu")
		(net "M_B_CPU1_SA_CB<7>")
	)
	(segment
		(start 57.087516 -269.45844)
		(end 57.087516 -269.800324)
		(width 0.18288)
		(layer "In2.Cu")
		(net "M_B_CPU1_SA_CB<7>")
	)
	(segment
		(start 83.824826 -258.534154)
		(end 81.706974 -260.652006)
		(width 0.088646)
		(layer "In2.Cu")
		(net "M_B_CPU1_SA_CB<7>")
	)
	(segment
		(start 84.495132 -258.237736)
		(end 84.229702 -258.237736)
		(width 0.088646)
		(layer "In2.Cu")
		(net "M_B_CPU1_SA_CB<7>")
	)
	(segment
		(start 64.65189 -268.098778)
		(end 64.45885 -268.291818)
		(width 0.18288)
		(layer "In2.Cu")
		(net "M_B_CPU1_SA_CB<7>")
	)
	(segment
		(start 69.690488 -265.173968)
		(end 69.417692 -265.173968)
		(width 0.18288)
		(layer "In2.Cu")
		(net "M_B_CPU1_SA_CB<7>")
	)
	(segment
		(start 52.519326 -270.895826)
		(end 52.26812 -271.147032)
		(width 0.18288)
		(layer "In2.Cu")
		(net "M_B_CPU1_SA_CB<7>")
	)
	(segment
		(start 55.369206 -270.895826)
		(end 52.519326 -270.895826)
		(width 0.18288)
		(layer "In2.Cu")
		(net "M_B_CPU1_SA_CB<7>")
	)
	(segment
		(start 60.573412 -268.47546)
		(end 60.573412 -268.948662)
		(width 0.18288)
		(layer "In2.Cu")
		(net "M_B_CPU1_SA_CB<7>")
	)
	(segment
		(start 60.380372 -269.141702)
		(end 60.094368 -269.141702)
		(width 0.18288)
		(layer "In2.Cu")
		(net "M_B_CPU1_SA_CB<7>")
	)
	(segment
		(start 58.883042 -269.993364)
		(end 57.984136 -269.993364)
		(width 0.18288)
		(layer "In2.Cu")
		(net "M_B_CPU1_SA_CB<7>")
	)
	(segment
		(start 63.67018 -268.336268)
		(end 63.553594 -268.055344)
		(width 0.18288)
		(layer "In2.Cu")
		(net "M_B_CPU1_SA_CB<7>")
	)
	(segment
		(start 69.784976 -264.54608)
		(end 69.915278 -264.676382)
		(width 0.18288)
		(layer "In2.Cu")
		(net "M_B_CPU1_SA_CB<7>")
	)
	(segment
		(start 57.087516 -269.800324)
		(end 56.894476 -269.993364)
		(width 0.18288)
		(layer "In2.Cu")
		(net "M_B_CPU1_SA_CB<7>")
	)
	(segment
		(start 71.334884 -263.529572)
		(end 70.68566 -264.178796)
		(width 0.18288)
		(layer "In2.Cu")
		(net "M_B_CPU1_SA_CB<7>")
	)
	(segment
		(start 67.924934 -266.666726)
		(end 67.924934 -266.939522)
		(width 0.18288)
		(layer "In2.Cu")
		(net "M_B_CPU1_SA_CB<7>")
	)
	(segment
		(start 60.094368 -269.141702)
		(end 60.03036 -269.20571)
		(width 0.18288)
		(layer "In2.Cu")
		(net "M_B_CPU1_SA_CB<7>")
	)
	(segment
		(start 67.794632 -266.263628)
		(end 67.794632 -266.536424)
		(width 0.18288)
		(layer "In2.Cu")
		(net "M_B_CPU1_SA_CB<7>")
	)
	(segment
		(start 81.706974 -260.652006)
		(end 81.550256 -260.652006)
		(width 0.088646)
		(layer "In2.Cu")
		(net "M_B_CPU1_SA_CB<7>")
	)
	(segment
		(start 57.598056 -269.2654)
		(end 57.280556 -269.2654)
		(width 0.18288)
		(layer "In2.Cu")
		(net "M_B_CPU1_SA_CB<7>")
	)
	(segment
		(start 60.573412 -268.948662)
		(end 60.380372 -269.141702)
		(width 0.18288)
		(layer "In2.Cu")
		(net "M_B_CPU1_SA_CB<7>")
	)
	(segment
		(start 63.008002 -268.072616)
		(end 62.903354 -268.324838)
		(width 0.18288)
		(layer "In2.Cu")
		(net "M_B_CPU1_SA_CB<7>")
	)
	(segment
		(start 63.077852 -268.745716)
		(end 62.973458 -268.998192)
		(width 0.18288)
		(layer "In2.Cu")
		(net "M_B_CPU1_SA_CB<7>")
	)
	(segment
		(start 61.276992 -268.46784)
		(end 61.083952 -268.2748)
		(width 0.18288)
		(layer "In2.Cu")
		(net "M_B_CPU1_SA_CB<7>")
	)
	(segment
		(start 59.082178 -269.39875)
		(end 59.082178 -269.794228)
		(width 0.18288)
		(layer "In2.Cu")
		(net "M_B_CPU1_SA_CB<7>")
	)
	(segment
		(start 68.920106 -265.671554)
		(end 68.920106 -265.94435)
		(width 0.18288)
		(layer "In2.Cu")
		(net "M_B_CPU1_SA_CB<7>")
	)
	(segment
		(start 60.03036 -269.20571)
		(end 59.275218 -269.20571)
		(width 0.18288)
		(layer "In2.Cu")
		(net "M_B_CPU1_SA_CB<7>")
	)
	(segment
		(start 62.626748 -269.141702)
		(end 61.470032 -269.141702)
		(width 0.18288)
		(layer "In2.Cu")
		(net "M_B_CPU1_SA_CB<7>")
	)
	(segment
		(start 64.256412 -268.291818)
		(end 64.238378 -268.309852)
		(width 0.18288)
		(layer "In2.Cu")
		(net "M_B_CPU1_SA_CB<7>")
	)
	(segment
		(start 56.894476 -269.993364)
		(end 56.00446 -269.993364)
		(width 0.18288)
		(layer "In2.Cu")
		(net "M_B_CPU1_SA_CB<7>")
	)
	(segment
		(start 68.789804 -265.541252)
		(end 68.920106 -265.671554)
		(width 0.18288)
		(layer "In2.Cu")
		(net "M_B_CPU1_SA_CB<7>")
	)
	(arc
		(start 88.537796 -258.313428)
		(mid 88.255094 -258.237686)
		(end 87.972392 -258.313428)
		(width 0.088646)
		(layer "In2.Cu")
		(net "M_B_CPU1_SA_CB<7>")
	)
	(arc
		(start 88.912192 -258.313428)
		(mid 88.724994 -258.363571)
		(end 88.537796 -258.313428)
		(width 0.088646)
		(layer "In2.Cu")
		(net "M_B_CPU1_SA_CB<7>")
	)
	(arc
		(start 87.032592 -258.313428)
		(mid 86.845394 -258.363571)
		(end 86.658196 -258.313428)
		(width 0.088646)
		(layer "In2.Cu")
		(net "M_B_CPU1_SA_CB<7>")
	)
	(arc
		(start 84.778596 -258.313428)
		(mid 84.641862 -258.256851)
		(end 84.495132 -258.237736)
		(width 0.088646)
		(layer "In2.Cu")
		(net "M_B_CPU1_SA_CB<7>")
	)
	(arc
		(start 85.152992 -258.313428)
		(mid 84.965794 -258.363571)
		(end 84.778596 -258.313428)
		(width 0.088646)
		(layer "In2.Cu")
		(net "M_B_CPU1_SA_CB<7>")
	)
	(arc
		(start 87.597996 -258.313428)
		(mid 87.315294 -258.237686)
		(end 87.032592 -258.313428)
		(width 0.088646)
		(layer "In2.Cu")
		(net "M_B_CPU1_SA_CB<7>")
	)
	(arc
		(start 86.092792 -258.313428)
		(mid 85.905594 -258.363571)
		(end 85.718396 -258.313428)
		(width 0.088646)
		(layer "In2.Cu")
		(net "M_B_CPU1_SA_CB<7>")
	)
	(arc
		(start 89.756742 -258.738116)
		(mid 89.667588 -258.492629)
		(end 89.477596 -258.313428)
		(width 0.088646)
		(layer "In2.Cu")
		(net "M_B_CPU1_SA_CB<7>")
	)
	(arc
		(start 86.658196 -258.313428)
		(mid 86.375494 -258.237686)
		(end 86.092792 -258.313428)
		(width 0.088646)
		(layer "In2.Cu")
		(net "M_B_CPU1_SA_CB<7>")
	)
	(arc
		(start 87.972392 -258.313428)
		(mid 87.785194 -258.363571)
		(end 87.597996 -258.313428)
		(width 0.088646)
		(layer "In2.Cu")
		(net "M_B_CPU1_SA_CB<7>")
	)
	(arc
		(start 89.477596 -258.313428)
		(mid 89.194894 -258.237686)
		(end 88.912192 -258.313428)
		(width 0.088646)
		(layer "In2.Cu")
		(net "M_B_CPU1_SA_CB<7>")
	)
	(arc
		(start 85.718396 -258.313428)
		(mid 85.435694 -258.237686)
		(end 85.152992 -258.313428)
		(width 0.088646)
		(layer "In2.Cu")
		(net "M_B_CPU1_SA_CB<7>")
	)
	(segment
		(start 90.604594 -259.08127)
		(end 90.604594 -259.616956)
		(width 0.20066)
		(layer "F.Cu")
		(net "M_B_CPU1_SA_CB<6>")
	)
	(segment
		(start 49.959514 -272.116804)
		(end 48.64481 -272.116804)
		(width 0.20066)
		(layer "F.Cu")
		(net "M_B_CPU1_SA_CB<6>")
	)
	(segment
		(start 48.64481 -272.116804)
		(end 48.432974 -272.32864)
		(width 0.20066)
		(layer "F.Cu")
		(net "M_B_CPU1_SA_CB<6>")
	)
	(segment
		(start 48.004476 -272.32864)
		(end 47.83709 -272.161254)
		(width 0.20066)
		(layer "F.Cu")
		(net "M_B_CPU1_SA_CB<6>")
	)
	(segment
		(start 47.83709 -271.835626)
		(end 47.693326 -271.691862)
		(width 0.20066)
		(layer "F.Cu")
		(net "M_B_CPU1_SA_CB<6>")
	)
	(segment
		(start 45.000418 -271.691862)
		(end 44.745402 -271.691862)
		(width 0.101854)
		(layer "F.Cu")
		(net "M_B_CPU1_SA_CB<6>")
	)
	(segment
		(start 90.604848 -259.081016)
		(end 90.604594 -259.08127)
		(width 0.20066)
		(layer "F.Cu")
		(net "M_B_CPU1_SA_CB<6>")
	)
	(segment
		(start 47.693326 -271.691862)
		(end 47.060358 -271.691862)
		(width 0.20066)
		(layer "F.Cu")
		(net "M_B_CPU1_SA_CB<6>")
	)
	(segment
		(start 48.432974 -272.32864)
		(end 48.004476 -272.32864)
		(width 0.20066)
		(layer "F.Cu")
		(net "M_B_CPU1_SA_CB<6>")
	)
	(segment
		(start 47.83709 -272.161254)
		(end 47.83709 -271.835626)
		(width 0.20066)
		(layer "F.Cu")
		(net "M_B_CPU1_SA_CB<6>")
	)
	(segment
		(start 44.745402 -271.691862)
		(end 44.735242 -271.681702)
		(width 0.101854)
		(layer "F.Cu")
		(net "M_B_CPU1_SA_CB<6>")
	)
	(segment
		(start 43.562778 -272.116804)
		(end 42.415714 -272.116804)
		(width 0.20066)
		(layer "F.Cu")
		(net "M_B_CPU1_SA_CB<6>")
	)
	(segment
		(start 47.060358 -271.691862)
		(end 45.000418 -271.691862)
		(width 0.1016)
		(layer "F.Cu")
		(net "M_B_CPU1_SA_CB<6>")
	)
	(segment
		(start 43.99788 -271.681702)
		(end 43.562778 -272.116804)
		(width 0.20066)
		(layer "F.Cu")
		(net "M_B_CPU1_SA_CB<6>")
	)
	(segment
		(start 44.735242 -271.681702)
		(end 43.99788 -271.681702)
		(width 0.20066)
		(layer "F.Cu")
		(net "M_B_CPU1_SA_CB<6>")
	)
	(segment
		(start 51.089814 -272.116804)
		(end 49.959514 -272.116804)
		(width 0.20066)
		(layer "F.Cu")
		(net "M_B_CPU1_SA_CB<6>")
	)
	(segment
		(start 67.259708 -269.57909)
		(end 67.259708 -269.851886)
		(width 0.18288)
		(layer "In2.Cu")
		(net "M_B_CPU1_SA_CB<6>")
	)
	(segment
		(start 71.737982 -265.100816)
		(end 71.614792 -264.977626)
		(width 0.18288)
		(layer "In2.Cu")
		(net "M_B_CPU1_SA_CB<6>")
	)
	(segment
		(start 83.589368 -259.4991)
		(end 81.745582 -261.342886)
		(width 0.088646)
		(layer "In2.Cu")
		(net "M_B_CPU1_SA_CB<6>")
	)
	(segment
		(start 72.60717 -264.105644)
		(end 72.235568 -264.477246)
		(width 0.18288)
		(layer "In2.Cu")
		(net "M_B_CPU1_SA_CB<6>")
	)
	(segment
		(start 59.244484 -271.168368)
		(end 59.244484 -271.770856)
		(width 0.18288)
		(layer "In2.Cu")
		(net "M_B_CPU1_SA_CB<6>")
	)
	(segment
		(start 70.020434 -267.09116)
		(end 69.747638 -267.09116)
		(width 0.18288)
		(layer "In2.Cu")
		(net "M_B_CPU1_SA_CB<6>")
	)
	(segment
		(start 68.03009 -269.081504)
		(end 67.757294 -269.081504)
		(width 0.18288)
		(layer "In2.Cu")
		(net "M_B_CPU1_SA_CB<6>")
	)
	(segment
		(start 70.61962 -265.972798)
		(end 70.346824 -265.972798)
		(width 0.18288)
		(layer "In2.Cu")
		(net "M_B_CPU1_SA_CB<6>")
	)
	(segment
		(start 71.614792 -264.977626)
		(end 71.341996 -264.977626)
		(width 0.18288)
		(layer "In2.Cu")
		(net "M_B_CPU1_SA_CB<6>")
	)
	(segment
		(start 70.122034 -266.470384)
		(end 70.245224 -266.593574)
		(width 0.18288)
		(layer "In2.Cu")
		(net "M_B_CPU1_SA_CB<6>")
	)
	(segment
		(start 59.5376 -270.875252)
		(end 59.244484 -271.168368)
		(width 0.18288)
		(layer "In2.Cu")
		(net "M_B_CPU1_SA_CB<6>")
	)
	(segment
		(start 51.089814 -272.167096)
		(end 51.089814 -272.116804)
		(width 0.18288)
		(layer "In2.Cu")
		(net "M_B_CPU1_SA_CB<6>")
	)
	(segment
		(start 61.761878 -270.875252)
		(end 59.5376 -270.875252)
		(width 0.18288)
		(layer "In2.Cu")
		(net "M_B_CPU1_SA_CB<6>")
	)
	(segment
		(start 51.753008 -272.83029)
		(end 51.089814 -272.167096)
		(width 0.18288)
		(layer "In2.Cu")
		(net "M_B_CPU1_SA_CB<6>")
	)
	(segment
		(start 62.032896 -271.14627)
		(end 61.761878 -270.875252)
		(width 0.18288)
		(layer "In2.Cu")
		(net "M_B_CPU1_SA_CB<6>")
	)
	(segment
		(start 69.747638 -267.09116)
		(end 69.624448 -266.96797)
		(width 0.18288)
		(layer "In2.Cu")
		(net "M_B_CPU1_SA_CB<6>")
	)
	(segment
		(start 71.015606 -266.095988)
		(end 70.74281 -266.095988)
		(width 0.18288)
		(layer "In2.Cu")
		(net "M_B_CPU1_SA_CB<6>")
	)
	(segment
		(start 54.426866 -272.786856)
		(end 53.81498 -272.17497)
		(width 0.18288)
		(layer "In2.Cu")
		(net "M_B_CPU1_SA_CB<6>")
	)
	(segment
		(start 62.677802 -270.96212)
		(end 62.493652 -271.14627)
		(width 0.18288)
		(layer "In2.Cu")
		(net "M_B_CPU1_SA_CB<6>")
	)
	(segment
		(start 59.071764 -271.943576)
		(end 58.553604 -271.943576)
		(width 0.18288)
		(layer "In2.Cu")
		(net "M_B_CPU1_SA_CB<6>")
	)
	(segment
		(start 90.604594 -259.616956)
		(end 90.29192 -259.61721)
		(width 0.088646)
		(layer "In2.Cu")
		(net "M_B_CPU1_SA_CB<6>")
	)
	(segment
		(start 58.553604 -271.943576)
		(end 57.919874 -271.309846)
		(width 0.18288)
		(layer "In2.Cu")
		(net "M_B_CPU1_SA_CB<6>")
	)
	(segment
		(start 68.13169 -268.187932)
		(end 68.13169 -268.460728)
		(width 0.18288)
		(layer "In2.Cu")
		(net "M_B_CPU1_SA_CB<6>")
	)
	(segment
		(start 63.349632 -270.29029)
		(end 62.919864 -270.29029)
		(width 0.18288)
		(layer "In2.Cu")
		(net "M_B_CPU1_SA_CB<6>")
	)
	(segment
		(start 62.493652 -271.14627)
		(end 62.032896 -271.14627)
		(width 0.18288)
		(layer "In2.Cu")
		(net "M_B_CPU1_SA_CB<6>")
	)
	(segment
		(start 67.136518 -269.183104)
		(end 67.136518 -269.4559)
		(width 0.18288)
		(layer "In2.Cu")
		(net "M_B_CPU1_SA_CB<6>")
	)
	(segment
		(start 81.745582 -261.342886)
		(end 81.550256 -261.342886)
		(width 0.088646)
		(layer "In2.Cu")
		(net "M_B_CPU1_SA_CB<6>")
	)
	(segment
		(start 68.13169 -268.460728)
		(end 68.25488 -268.583918)
		(width 0.18288)
		(layer "In2.Cu")
		(net "M_B_CPU1_SA_CB<6>")
	)
	(segment
		(start 69.126862 -267.465556)
		(end 69.250052 -267.588746)
		(width 0.18288)
		(layer "In2.Cu")
		(net "M_B_CPU1_SA_CB<6>")
	)
	(segment
		(start 71.240396 -265.871198)
		(end 71.015606 -266.095988)
		(width 0.18288)
		(layer "In2.Cu")
		(net "M_B_CPU1_SA_CB<6>")
	)
	(segment
		(start 68.25488 -268.856714)
		(end 68.03009 -269.081504)
		(width 0.18288)
		(layer "In2.Cu")
		(net "M_B_CPU1_SA_CB<6>")
	)
	(segment
		(start 73.00595 -264.105644)
		(end 72.60717 -264.105644)
		(width 0.18288)
		(layer "In2.Cu")
		(net "M_B_CPU1_SA_CB<6>")
	)
	(segment
		(start 69.250052 -267.588746)
		(end 69.250052 -267.861542)
		(width 0.18288)
		(layer "In2.Cu")
		(net "M_B_CPU1_SA_CB<6>")
	)
	(segment
		(start 62.677802 -270.532352)
		(end 62.677802 -270.96212)
		(width 0.18288)
		(layer "In2.Cu")
		(net "M_B_CPU1_SA_CB<6>")
	)
	(segment
		(start 83.878166 -259.051806)
		(end 83.589368 -259.340604)
		(width 0.088646)
		(layer "In2.Cu")
		(net "M_B_CPU1_SA_CB<6>")
	)
	(segment
		(start 57.919874 -271.309846)
		(end 57.0484 -271.309846)
		(width 0.18288)
		(layer "In2.Cu")
		(net "M_B_CPU1_SA_CB<6>")
	)
	(segment
		(start 69.126862 -267.19276)
		(end 69.126862 -267.465556)
		(width 0.18288)
		(layer "In2.Cu")
		(net "M_B_CPU1_SA_CB<6>")
	)
	(segment
		(start 62.919864 -270.29029)
		(end 62.677802 -270.532352)
		(width 0.18288)
		(layer "In2.Cu")
		(net "M_B_CPU1_SA_CB<6>")
	)
	(segment
		(start 81.550256 -261.342886)
		(end 77.655928 -261.342886)
		(width 0.18288)
		(layer "In2.Cu")
		(net "M_B_CPU1_SA_CB<6>")
	)
	(segment
		(start 69.250052 -267.861542)
		(end 69.025262 -268.086332)
		(width 0.18288)
		(layer "In2.Cu")
		(net "M_B_CPU1_SA_CB<6>")
	)
	(segment
		(start 56.370474 -271.987772)
		(end 55.285132 -271.987772)
		(width 0.18288)
		(layer "In2.Cu")
		(net "M_B_CPU1_SA_CB<6>")
	)
	(segment
		(start 71.240396 -265.598402)
		(end 71.240396 -265.871198)
		(width 0.18288)
		(layer "In2.Cu")
		(net "M_B_CPU1_SA_CB<6>")
	)
	(segment
		(start 72.010778 -265.100816)
		(end 71.737982 -265.100816)
		(width 0.18288)
		(layer "In2.Cu")
		(net "M_B_CPU1_SA_CB<6>")
	)
	(segment
		(start 71.117206 -265.202416)
		(end 71.117206 -265.475212)
		(width 0.18288)
		(layer "In2.Cu")
		(net "M_B_CPU1_SA_CB<6>")
	)
	(segment
		(start 55.125112 -272.147792)
		(end 55.125112 -272.624042)
		(width 0.18288)
		(layer "In2.Cu")
		(net "M_B_CPU1_SA_CB<6>")
	)
	(segment
		(start 72.235568 -264.876026)
		(end 72.010778 -265.100816)
		(width 0.18288)
		(layer "In2.Cu")
		(net "M_B_CPU1_SA_CB<6>")
	)
	(segment
		(start 67.136518 -269.4559)
		(end 67.259708 -269.57909)
		(width 0.18288)
		(layer "In2.Cu")
		(net "M_B_CPU1_SA_CB<6>")
	)
	(segment
		(start 68.35648 -267.963142)
		(end 68.13169 -268.187932)
		(width 0.18288)
		(layer "In2.Cu")
		(net "M_B_CPU1_SA_CB<6>")
	)
	(segment
		(start 67.757294 -269.081504)
		(end 67.634104 -268.958314)
		(width 0.18288)
		(layer "In2.Cu")
		(net "M_B_CPU1_SA_CB<6>")
	)
	(segment
		(start 68.752466 -268.086332)
		(end 68.629276 -267.963142)
		(width 0.18288)
		(layer "In2.Cu")
		(net "M_B_CPU1_SA_CB<6>")
	)
	(segment
		(start 77.655928 -261.342886)
		(end 76.51496 -262.483854)
		(width 0.18288)
		(layer "In2.Cu")
		(net "M_B_CPU1_SA_CB<6>")
	)
	(segment
		(start 67.259708 -269.851886)
		(end 66.821812 -270.289782)
		(width 0.18288)
		(layer "In2.Cu")
		(net "M_B_CPU1_SA_CB<6>")
	)
	(segment
		(start 52.9336 -272.17497)
		(end 52.27828 -272.83029)
		(width 0.18288)
		(layer "In2.Cu")
		(net "M_B_CPU1_SA_CB<6>")
	)
	(segment
		(start 69.025262 -268.086332)
		(end 68.752466 -268.086332)
		(width 0.18288)
		(layer "In2.Cu")
		(net "M_B_CPU1_SA_CB<6>")
	)
	(segment
		(start 67.634104 -268.958314)
		(end 67.361308 -268.958314)
		(width 0.18288)
		(layer "In2.Cu")
		(net "M_B_CPU1_SA_CB<6>")
	)
	(segment
		(start 55.125112 -272.624042)
		(end 54.962298 -272.786856)
		(width 0.18288)
		(layer "In2.Cu")
		(net "M_B_CPU1_SA_CB<6>")
	)
	(segment
		(start 68.25488 -268.583918)
		(end 68.25488 -268.856714)
		(width 0.18288)
		(layer "In2.Cu")
		(net "M_B_CPU1_SA_CB<6>")
	)
	(segment
		(start 55.285132 -271.987772)
		(end 55.125112 -272.147792)
		(width 0.18288)
		(layer "In2.Cu")
		(net "M_B_CPU1_SA_CB<6>")
	)
	(segment
		(start 57.0484 -271.309846)
		(end 56.370474 -271.987772)
		(width 0.18288)
		(layer "In2.Cu")
		(net "M_B_CPU1_SA_CB<6>")
	)
	(segment
		(start 90.29192 -259.61721)
		(end 90.226388 -259.551678)
		(width 0.088646)
		(layer "In2.Cu")
		(net "M_B_CPU1_SA_CB<6>")
	)
	(segment
		(start 69.351652 -266.96797)
		(end 69.126862 -267.19276)
		(width 0.18288)
		(layer "In2.Cu")
		(net "M_B_CPU1_SA_CB<6>")
	)
	(segment
		(start 70.245224 -266.593574)
		(end 70.245224 -266.86637)
		(width 0.18288)
		(layer "In2.Cu")
		(net "M_B_CPU1_SA_CB<6>")
	)
	(segment
		(start 53.81498 -272.17497)
		(end 52.9336 -272.17497)
		(width 0.18288)
		(layer "In2.Cu")
		(net "M_B_CPU1_SA_CB<6>")
	)
	(segment
		(start 65.848992 -270.013176)
		(end 63.626746 -270.013176)
		(width 0.18288)
		(layer "In2.Cu")
		(net "M_B_CPU1_SA_CB<6>")
	)
	(segment
		(start 76.51496 -262.483854)
		(end 73.29043 -263.821164)
		(width 0.18288)
		(layer "In2.Cu")
		(net "M_B_CPU1_SA_CB<6>")
	)
	(segment
		(start 63.626746 -270.013176)
		(end 63.349632 -270.29029)
		(width 0.18288)
		(layer "In2.Cu")
		(net "M_B_CPU1_SA_CB<6>")
	)
	(segment
		(start 69.624448 -266.96797)
		(end 69.351652 -266.96797)
		(width 0.18288)
		(layer "In2.Cu")
		(net "M_B_CPU1_SA_CB<6>")
	)
	(segment
		(start 70.74281 -266.095988)
		(end 70.61962 -265.972798)
		(width 0.18288)
		(layer "In2.Cu")
		(net "M_B_CPU1_SA_CB<6>")
	)
	(segment
		(start 70.122034 -266.197588)
		(end 70.122034 -266.470384)
		(width 0.18288)
		(layer "In2.Cu")
		(net "M_B_CPU1_SA_CB<6>")
	)
	(segment
		(start 52.27828 -272.83029)
		(end 51.753008 -272.83029)
		(width 0.18288)
		(layer "In2.Cu")
		(net "M_B_CPU1_SA_CB<6>")
	)
	(segment
		(start 84.025994 -259.051806)
		(end 83.878166 -259.051806)
		(width 0.088646)
		(layer "In2.Cu")
		(net "M_B_CPU1_SA_CB<6>")
	)
	(segment
		(start 71.117206 -265.475212)
		(end 71.240396 -265.598402)
		(width 0.18288)
		(layer "In2.Cu")
		(net "M_B_CPU1_SA_CB<6>")
	)
	(segment
		(start 66.821812 -270.289782)
		(end 66.125598 -270.289782)
		(width 0.18288)
		(layer "In2.Cu")
		(net "M_B_CPU1_SA_CB<6>")
	)
	(segment
		(start 68.629276 -267.963142)
		(end 68.35648 -267.963142)
		(width 0.18288)
		(layer "In2.Cu")
		(net "M_B_CPU1_SA_CB<6>")
	)
	(segment
		(start 83.589368 -259.340604)
		(end 83.589368 -259.4991)
		(width 0.088646)
		(layer "In2.Cu")
		(net "M_B_CPU1_SA_CB<6>")
	)
	(segment
		(start 73.29043 -263.821164)
		(end 73.00595 -264.105644)
		(width 0.18288)
		(layer "In2.Cu")
		(net "M_B_CPU1_SA_CB<6>")
	)
	(segment
		(start 88.084914 -259.13715)
		(end 88.067896 -259.127498)
		(width 0.088646)
		(layer "In2.Cu")
		(net "M_B_CPU1_SA_CB<6>")
	)
	(segment
		(start 59.244484 -271.770856)
		(end 59.071764 -271.943576)
		(width 0.18288)
		(layer "In2.Cu")
		(net "M_B_CPU1_SA_CB<6>")
	)
	(segment
		(start 72.235568 -264.477246)
		(end 72.235568 -264.876026)
		(width 0.18288)
		(layer "In2.Cu")
		(net "M_B_CPU1_SA_CB<6>")
	)
	(segment
		(start 67.361308 -268.958314)
		(end 67.136518 -269.183104)
		(width 0.18288)
		(layer "In2.Cu")
		(net "M_B_CPU1_SA_CB<6>")
	)
	(segment
		(start 71.341996 -264.977626)
		(end 71.117206 -265.202416)
		(width 0.18288)
		(layer "In2.Cu")
		(net "M_B_CPU1_SA_CB<6>")
	)
	(segment
		(start 88.442292 -259.127752)
		(end 88.42883 -259.135372)
		(width 0.088646)
		(layer "In2.Cu")
		(net "M_B_CPU1_SA_CB<6>")
	)
	(segment
		(start 70.245224 -266.86637)
		(end 70.020434 -267.09116)
		(width 0.18288)
		(layer "In2.Cu")
		(net "M_B_CPU1_SA_CB<6>")
	)
	(segment
		(start 66.125598 -270.289782)
		(end 65.848992 -270.013176)
		(width 0.18288)
		(layer "In2.Cu")
		(net "M_B_CPU1_SA_CB<6>")
	)
	(segment
		(start 54.962298 -272.786856)
		(end 54.426866 -272.786856)
		(width 0.18288)
		(layer "In2.Cu")
		(net "M_B_CPU1_SA_CB<6>")
	)
	(segment
		(start 70.346824 -265.972798)
		(end 70.122034 -266.197588)
		(width 0.18288)
		(layer "In2.Cu")
		(net "M_B_CPU1_SA_CB<6>")
	)
	(arc
		(start 85.248496 -259.127498)
		(mid 84.965794 -259.051722)
		(end 84.683092 -259.127498)
		(width 0.088646)
		(layer "In2.Cu")
		(net "M_B_CPU1_SA_CB<6>")
	)
	(arc
		(start 88.067896 -259.127498)
		(mid 87.785194 -259.051722)
		(end 87.502492 -259.127498)
		(width 0.088646)
		(layer "In2.Cu")
		(net "M_B_CPU1_SA_CB<6>")
	)
	(arc
		(start 86.562692 -259.127498)
		(mid 86.375494 -259.177641)
		(end 86.188296 -259.127498)
		(width 0.088646)
		(layer "In2.Cu")
		(net "M_B_CPU1_SA_CB<6>")
	)
	(arc
		(start 90.226388 -259.551678)
		(mid 89.918552 -259.111948)
		(end 89.382092 -259.127752)
		(width 0.088646)
		(layer "In2.Cu")
		(net "M_B_CPU1_SA_CB<6>")
	)
	(arc
		(start 84.683092 -259.127498)
		(mid 84.495894 -259.177641)
		(end 84.308696 -259.127498)
		(width 0.088646)
		(layer "In2.Cu")
		(net "M_B_CPU1_SA_CB<6>")
	)
	(arc
		(start 89.382092 -259.127752)
		(mid 89.194894 -259.177895)
		(end 89.007696 -259.127752)
		(width 0.088646)
		(layer "In2.Cu")
		(net "M_B_CPU1_SA_CB<6>")
	)
	(arc
		(start 86.188296 -259.127498)
		(mid 85.905594 -259.051722)
		(end 85.622892 -259.127498)
		(width 0.088646)
		(layer "In2.Cu")
		(net "M_B_CPU1_SA_CB<6>")
	)
	(arc
		(start 85.622892 -259.127498)
		(mid 85.435694 -259.177641)
		(end 85.248496 -259.127498)
		(width 0.088646)
		(layer "In2.Cu")
		(net "M_B_CPU1_SA_CB<6>")
	)
	(arc
		(start 89.007696 -259.127752)
		(mid 88.724994 -259.051976)
		(end 88.442292 -259.127752)
		(width 0.088646)
		(layer "In2.Cu")
		(net "M_B_CPU1_SA_CB<6>")
	)
	(arc
		(start 87.502492 -259.127498)
		(mid 87.315294 -259.177641)
		(end 87.128096 -259.127498)
		(width 0.088646)
		(layer "In2.Cu")
		(net "M_B_CPU1_SA_CB<6>")
	)
	(arc
		(start 87.128096 -259.127498)
		(mid 86.845394 -259.051722)
		(end 86.562692 -259.127498)
		(width 0.088646)
		(layer "In2.Cu")
		(net "M_B_CPU1_SA_CB<6>")
	)
	(arc
		(start 88.42883 -259.135372)
		(mid 88.257112 -259.181784)
		(end 88.084914 -259.13715)
		(width 0.088646)
		(layer "In2.Cu")
		(net "M_B_CPU1_SA_CB<6>")
	)
	(arc
		(start 84.308696 -259.127498)
		(mid 84.17233 -259.07102)
		(end 84.025994 -259.051806)
		(width 0.088646)
		(layer "In2.Cu")
		(net "M_B_CPU1_SA_CB<6>")
	)
	(segment
		(start 89.194894 -258.2672)
		(end 89.194894 -258.80314)
		(width 0.20066)
		(layer "F.Cu")
		(net "M_B_CPU1_SA_CB<5>")
	)
	(segment
		(start 40.520112 -271.323562)
		(end 40.36568 -271.477994)
		(width 0.20066)
		(layer "F.Cu")
		(net "M_B_CPU1_SA_CB<5>")
	)
	(segment
		(start 43.285918 -270.841724)
		(end 41.3004 -270.841724)
		(width 0.1016)
		(layer "F.Cu")
		(net "M_B_CPU1_SA_CB<5>")
	)
	(segment
		(start 41.29151 -270.832834)
		(end 40.682672 -270.832834)
		(width 0.20066)
		(layer "F.Cu")
		(net "M_B_CPU1_SA_CB<5>")
	)
	(segment
		(start 43.795188 -270.841724)
		(end 43.616626 -270.841724)
		(width 0.20066)
		(layer "F.Cu")
		(net "M_B_CPU1_SA_CB<5>")
	)
	(segment
		(start 39.861236 -271.477994)
		(end 39.649908 -271.266666)
		(width 0.20066)
		(layer "F.Cu")
		(net "M_B_CPU1_SA_CB<5>")
	)
	(segment
		(start 40.36568 -271.477994)
		(end 39.861236 -271.477994)
		(width 0.20066)
		(layer "F.Cu")
		(net "M_B_CPU1_SA_CB<5>")
	)
	(segment
		(start 39.649908 -271.266666)
		(end 38.315646 -271.266666)
		(width 0.20066)
		(layer "F.Cu")
		(net "M_B_CPU1_SA_CB<5>")
	)
	(segment
		(start 41.3004 -270.841724)
		(end 41.29151 -270.832834)
		(width 0.1016)
		(layer "F.Cu")
		(net "M_B_CPU1_SA_CB<5>")
	)
	(segment
		(start 46.964346 -271.266666)
		(end 45.859446 -271.266666)
		(width 0.20066)
		(layer "F.Cu")
		(net "M_B_CPU1_SA_CB<5>")
	)
	(segment
		(start 43.616626 -270.841724)
		(end 43.285918 -270.841724)
		(width 0.101854)
		(layer "F.Cu")
		(net "M_B_CPU1_SA_CB<5>")
	)
	(segment
		(start 44.22013 -271.266666)
		(end 43.795188 -270.841724)
		(width 0.20066)
		(layer "F.Cu")
		(net "M_B_CPU1_SA_CB<5>")
	)
	(segment
		(start 40.682672 -270.832834)
		(end 40.520112 -270.995394)
		(width 0.20066)
		(layer "F.Cu")
		(net "M_B_CPU1_SA_CB<5>")
	)
	(segment
		(start 40.520112 -270.995394)
		(end 40.520112 -271.323562)
		(width 0.20066)
		(layer "F.Cu")
		(net "M_B_CPU1_SA_CB<5>")
	)
	(segment
		(start 45.859446 -271.266666)
		(end 44.22013 -271.266666)
		(width 0.20066)
		(layer "F.Cu")
		(net "M_B_CPU1_SA_CB<5>")
	)
	(segment
		(start 71.652384 -263.948418)
		(end 66.4591 -269.141702)
		(width 0.18288)
		(layer "In2.Cu")
		(net "M_B_CPU1_SA_CB<5>")
	)
	(segment
		(start 48.326802 -271.688052)
		(end 48.326802 -270.333724)
		(width 0.18288)
		(layer "In2.Cu")
		(net "M_B_CPU1_SA_CB<5>")
	)
	(segment
		(start 59.63031 -269.967202)
		(end 58.805064 -270.792448)
		(width 0.18288)
		(layer "In2.Cu")
		(net "M_B_CPU1_SA_CB<5>")
	)
	(segment
		(start 51.588416 -271.665954)
		(end 51.562508 -271.691862)
		(width 0.18288)
		(layer "In2.Cu")
		(net "M_B_CPU1_SA_CB<5>")
	)
	(segment
		(start 65.665096 -269.141702)
		(end 65.311274 -269.495524)
		(width 0.18288)
		(layer "In2.Cu")
		(net "M_B_CPU1_SA_CB<5>")
	)
	(segment
		(start 64.21882 -269.135098)
		(end 63.6397 -269.135098)
		(width 0.18288)
		(layer "In2.Cu")
		(net "M_B_CPU1_SA_CB<5>")
	)
	(segment
		(start 63.6397 -269.135098)
		(end 63.099188 -269.67561)
		(width 0.18288)
		(layer "In2.Cu")
		(net "M_B_CPU1_SA_CB<5>")
	)
	(segment
		(start 81.550256 -260.997446)
		(end 77.282548 -260.997446)
		(width 0.18288)
		(layer "In2.Cu")
		(net "M_B_CPU1_SA_CB<5>")
	)
	(segment
		(start 62.495938 -269.99184)
		(end 61.57595 -269.99184)
		(width 0.18288)
		(layer "In2.Cu")
		(net "M_B_CPU1_SA_CB<5>")
	)
	(segment
		(start 82.206338 -260.445504)
		(end 82.206338 -260.529324)
		(width 0.088646)
		(layer "In2.Cu")
		(net "M_B_CPU1_SA_CB<5>")
	)
	(segment
		(start 60.042552 -269.967202)
		(end 59.63031 -269.967202)
		(width 0.18288)
		(layer "In2.Cu")
		(net "M_B_CPU1_SA_CB<5>")
	)
	(segment
		(start 82.206338 -260.529324)
		(end 81.738216 -260.997446)
		(width 0.088646)
		(layer "In2.Cu")
		(net "M_B_CPU1_SA_CB<5>")
	)
	(segment
		(start 48.519842 -271.881092)
		(end 48.326802 -271.688052)
		(width 0.18288)
		(layer "In2.Cu")
		(net "M_B_CPU1_SA_CB<5>")
	)
	(segment
		(start 54.438296 -271.469358)
		(end 54.2417 -271.665954)
		(width 0.18288)
		(layer "In2.Cu")
		(net "M_B_CPU1_SA_CB<5>")
	)
	(segment
		(start 58.805064 -270.792448)
		(end 56.213502 -270.792448)
		(width 0.18288)
		(layer "In2.Cu")
		(net "M_B_CPU1_SA_CB<5>")
	)
	(segment
		(start 76.227178 -262.052816)
		(end 71.652384 -263.948418)
		(width 0.18288)
		(layer "In2.Cu")
		(net "M_B_CPU1_SA_CB<5>")
	)
	(segment
		(start 49.885346 -271.178782)
		(end 49.612042 -271.178782)
		(width 0.18288)
		(layer "In2.Cu")
		(net "M_B_CPU1_SA_CB<5>")
	)
	(segment
		(start 61.20765 -270.36014)
		(end 60.43549 -270.36014)
		(width 0.18288)
		(layer "In2.Cu")
		(net "M_B_CPU1_SA_CB<5>")
	)
	(segment
		(start 77.282548 -260.997446)
		(end 76.227178 -262.052816)
		(width 0.18288)
		(layer "In2.Cu")
		(net "M_B_CPU1_SA_CB<5>")
	)
	(segment
		(start 60.43549 -270.36014)
		(end 60.042552 -269.967202)
		(width 0.18288)
		(layer "In2.Cu")
		(net "M_B_CPU1_SA_CB<5>")
	)
	(segment
		(start 49.612042 -271.178782)
		(end 48.909732 -271.881092)
		(width 0.18288)
		(layer "In2.Cu")
		(net "M_B_CPU1_SA_CB<5>")
	)
	(segment
		(start 48.133762 -270.140684)
		(end 47.834296 -270.140684)
		(width 0.18288)
		(layer "In2.Cu")
		(net "M_B_CPU1_SA_CB<5>")
	)
	(segment
		(start 89.390982 -258.483862)
		(end 89.382092 -258.478782)
		(width 0.088646)
		(layer "In2.Cu")
		(net "M_B_CPU1_SA_CB<5>")
	)
	(segment
		(start 54.2417 -271.665954)
		(end 51.588416 -271.665954)
		(width 0.18288)
		(layer "In2.Cu")
		(net "M_B_CPU1_SA_CB<5>")
	)
	(segment
		(start 66.4591 -269.141702)
		(end 65.665096 -269.141702)
		(width 0.18288)
		(layer "In2.Cu")
		(net "M_B_CPU1_SA_CB<5>")
	)
	(segment
		(start 83.864196 -258.787646)
		(end 82.206338 -260.445504)
		(width 0.088646)
		(layer "In2.Cu")
		(net "M_B_CPU1_SA_CB<5>")
	)
	(segment
		(start 47.623222 -270.351758)
		(end 47.623222 -271.073626)
		(width 0.18288)
		(layer "In2.Cu")
		(net "M_B_CPU1_SA_CB<5>")
	)
	(segment
		(start 55.536592 -271.469358)
		(end 54.438296 -271.469358)
		(width 0.18288)
		(layer "In2.Cu")
		(net "M_B_CPU1_SA_CB<5>")
	)
	(segment
		(start 89.194894 -258.80314)
		(end 89.507822 -258.80314)
		(width 0.088646)
		(layer "In2.Cu")
		(net "M_B_CPU1_SA_CB<5>")
	)
	(segment
		(start 47.430182 -271.266666)
		(end 46.964346 -271.266666)
		(width 0.18288)
		(layer "In2.Cu")
		(net "M_B_CPU1_SA_CB<5>")
	)
	(segment
		(start 56.213502 -270.792448)
		(end 55.536592 -271.469358)
		(width 0.18288)
		(layer "In2.Cu")
		(net "M_B_CPU1_SA_CB<5>")
	)
	(segment
		(start 48.326802 -270.333724)
		(end 48.133762 -270.140684)
		(width 0.18288)
		(layer "In2.Cu")
		(net "M_B_CPU1_SA_CB<5>")
	)
	(segment
		(start 63.099188 -269.67561)
		(end 62.812168 -269.67561)
		(width 0.18288)
		(layer "In2.Cu")
		(net "M_B_CPU1_SA_CB<5>")
	)
	(segment
		(start 81.738216 -260.997446)
		(end 81.550256 -260.997446)
		(width 0.088646)
		(layer "In2.Cu")
		(net "M_B_CPU1_SA_CB<5>")
	)
	(segment
		(start 47.623222 -271.073626)
		(end 47.430182 -271.266666)
		(width 0.18288)
		(layer "In2.Cu")
		(net "M_B_CPU1_SA_CB<5>")
	)
	(segment
		(start 62.812168 -269.67561)
		(end 62.495938 -269.99184)
		(width 0.18288)
		(layer "In2.Cu")
		(net "M_B_CPU1_SA_CB<5>")
	)
	(segment
		(start 50.398426 -271.691862)
		(end 49.885346 -271.178782)
		(width 0.18288)
		(layer "In2.Cu")
		(net "M_B_CPU1_SA_CB<5>")
	)
	(segment
		(start 84.22259 -258.519168)
		(end 83.954112 -258.787646)
		(width 0.088646)
		(layer "In2.Cu")
		(net "M_B_CPU1_SA_CB<5>")
	)
	(segment
		(start 89.507822 -258.80314)
		(end 89.564972 -258.74599)
		(width 0.088646)
		(layer "In2.Cu")
		(net "M_B_CPU1_SA_CB<5>")
	)
	(segment
		(start 65.311274 -269.495524)
		(end 64.579246 -269.495524)
		(width 0.18288)
		(layer "In2.Cu")
		(net "M_B_CPU1_SA_CB<5>")
	)
	(segment
		(start 83.954112 -258.787646)
		(end 83.864196 -258.787646)
		(width 0.088646)
		(layer "In2.Cu")
		(net "M_B_CPU1_SA_CB<5>")
	)
	(segment
		(start 47.834296 -270.140684)
		(end 47.623222 -270.351758)
		(width 0.18288)
		(layer "In2.Cu")
		(net "M_B_CPU1_SA_CB<5>")
	)
	(segment
		(start 61.57595 -269.99184)
		(end 61.20765 -270.36014)
		(width 0.18288)
		(layer "In2.Cu")
		(net "M_B_CPU1_SA_CB<5>")
	)
	(segment
		(start 51.562508 -271.691862)
		(end 50.398426 -271.691862)
		(width 0.18288)
		(layer "In2.Cu")
		(net "M_B_CPU1_SA_CB<5>")
	)
	(segment
		(start 48.909732 -271.881092)
		(end 48.519842 -271.881092)
		(width 0.18288)
		(layer "In2.Cu")
		(net "M_B_CPU1_SA_CB<5>")
	)
	(segment
		(start 64.579246 -269.495524)
		(end 64.21882 -269.135098)
		(width 0.18288)
		(layer "In2.Cu")
		(net "M_B_CPU1_SA_CB<5>")
	)
	(arc
		(start 87.128096 -258.478782)
		(mid 86.845394 -258.554524)
		(end 86.562692 -258.478782)
		(width 0.088646)
		(layer "In2.Cu")
		(net "M_B_CPU1_SA_CB<5>")
	)
	(arc
		(start 88.442292 -258.478782)
		(mid 88.255094 -258.428639)
		(end 88.067896 -258.478782)
		(width 0.088646)
		(layer "In2.Cu")
		(net "M_B_CPU1_SA_CB<5>")
	)
	(arc
		(start 86.562692 -258.478782)
		(mid 86.375494 -258.428639)
		(end 86.188296 -258.478782)
		(width 0.088646)
		(layer "In2.Cu")
		(net "M_B_CPU1_SA_CB<5>")
	)
	(arc
		(start 87.502492 -258.478782)
		(mid 87.315294 -258.428639)
		(end 87.128096 -258.478782)
		(width 0.088646)
		(layer "In2.Cu")
		(net "M_B_CPU1_SA_CB<5>")
	)
	(arc
		(start 88.067896 -258.478782)
		(mid 87.785194 -258.554524)
		(end 87.502492 -258.478782)
		(width 0.088646)
		(layer "In2.Cu")
		(net "M_B_CPU1_SA_CB<5>")
	)
	(arc
		(start 89.382092 -258.478782)
		(mid 89.194894 -258.428639)
		(end 89.007696 -258.478782)
		(width 0.088646)
		(layer "In2.Cu")
		(net "M_B_CPU1_SA_CB<5>")
	)
	(arc
		(start 85.622892 -258.478782)
		(mid 85.435694 -258.428639)
		(end 85.248496 -258.478782)
		(width 0.088646)
		(layer "In2.Cu")
		(net "M_B_CPU1_SA_CB<5>")
	)
	(arc
		(start 86.188296 -258.478782)
		(mid 85.905594 -258.554524)
		(end 85.622892 -258.478782)
		(width 0.088646)
		(layer "In2.Cu")
		(net "M_B_CPU1_SA_CB<5>")
	)
	(arc
		(start 89.564972 -258.74599)
		(mid 89.506853 -258.595749)
		(end 89.390982 -258.483862)
		(width 0.088646)
		(layer "In2.Cu")
		(net "M_B_CPU1_SA_CB<5>")
	)
	(arc
		(start 84.308696 -258.478782)
		(mid 84.266497 -258.500796)
		(end 84.22259 -258.519168)
		(width 0.088646)
		(layer "In2.Cu")
		(net "M_B_CPU1_SA_CB<5>")
	)
	(arc
		(start 89.007696 -258.478782)
		(mid 88.724994 -258.554524)
		(end 88.442292 -258.478782)
		(width 0.088646)
		(layer "In2.Cu")
		(net "M_B_CPU1_SA_CB<5>")
	)
	(arc
		(start 85.248496 -258.478782)
		(mid 84.965794 -258.554524)
		(end 84.683092 -258.478782)
		(width 0.088646)
		(layer "In2.Cu")
		(net "M_B_CPU1_SA_CB<5>")
	)
	(arc
		(start 84.683092 -258.478782)
		(mid 84.495894 -258.428639)
		(end 84.308696 -258.478782)
		(width 0.088646)
		(layer "In2.Cu")
		(net "M_B_CPU1_SA_CB<5>")
	)
	(segment
		(start 39.649908 -272.966688)
		(end 38.315646 -272.966688)
		(width 0.20066)
		(layer "F.Cu")
		(net "M_B_CPU1_SA_CB<4>")
	)
	(segment
		(start 44.065444 -272.541746)
		(end 43.616626 -272.541746)
		(width 0.20066)
		(layer "F.Cu")
		(net "M_B_CPU1_SA_CB<4>")
	)
	(segment
		(start 41.299638 -272.541746)
		(end 41.29151 -272.533618)
		(width 0.101854)
		(layer "F.Cu")
		(net "M_B_CPU1_SA_CB<4>")
	)
	(segment
		(start 39.888668 -273.205448)
		(end 39.649908 -272.966688)
		(width 0.20066)
		(layer "F.Cu")
		(net "M_B_CPU1_SA_CB<4>")
	)
	(segment
		(start 40.729662 -272.533618)
		(end 40.520112 -272.743168)
		(width 0.20066)
		(layer "F.Cu")
		(net "M_B_CPU1_SA_CB<4>")
	)
	(segment
		(start 41.29151 -272.533618)
		(end 40.729662 -272.533618)
		(width 0.20066)
		(layer "F.Cu")
		(net "M_B_CPU1_SA_CB<4>")
	)
	(segment
		(start 43.616626 -272.541746)
		(end 41.547542 -272.541746)
		(width 0.1016)
		(layer "F.Cu")
		(net "M_B_CPU1_SA_CB<4>")
	)
	(segment
		(start 44.490386 -272.966688)
		(end 44.065444 -272.541746)
		(width 0.20066)
		(layer "F.Cu")
		(net "M_B_CPU1_SA_CB<4>")
	)
	(segment
		(start 41.547542 -272.541746)
		(end 41.299638 -272.541746)
		(width 0.101854)
		(layer "F.Cu")
		(net "M_B_CPU1_SA_CB<4>")
	)
	(segment
		(start 40.520112 -272.743168)
		(end 40.520112 -273.032728)
		(width 0.20066)
		(layer "F.Cu")
		(net "M_B_CPU1_SA_CB<4>")
	)
	(segment
		(start 46.964346 -272.966688)
		(end 45.859446 -272.966688)
		(width 0.20066)
		(layer "F.Cu")
		(net "M_B_CPU1_SA_CB<4>")
	)
	(segment
		(start 40.520112 -273.032728)
		(end 40.347392 -273.205448)
		(width 0.20066)
		(layer "F.Cu")
		(net "M_B_CPU1_SA_CB<4>")
	)
	(segment
		(start 45.859446 -272.966688)
		(end 44.490386 -272.966688)
		(width 0.20066)
		(layer "F.Cu")
		(net "M_B_CPU1_SA_CB<4>")
	)
	(segment
		(start 88.724994 -259.08127)
		(end 88.724994 -259.616956)
		(width 0.20066)
		(layer "F.Cu")
		(net "M_B_CPU1_SA_CB<4>")
	)
	(segment
		(start 88.725248 -259.081016)
		(end 88.724994 -259.08127)
		(width 0.20066)
		(layer "F.Cu")
		(net "M_B_CPU1_SA_CB<4>")
	)
	(segment
		(start 40.347392 -273.205448)
		(end 39.888668 -273.205448)
		(width 0.20066)
		(layer "F.Cu")
		(net "M_B_CPU1_SA_CB<4>")
	)
	(segment
		(start 88.724994 -259.616956)
		(end 88.210644 -259.431282)
		(width 0.088646)
		(layer "In2.Cu")
		(net "M_B_CPU1_SA_CB<4>")
	)
	(segment
		(start 83.957668 -259.264912)
		(end 83.795362 -259.427218)
		(width 0.088646)
		(layer "In2.Cu")
		(net "M_B_CPU1_SA_CB<4>")
	)
	(segment
		(start 47.949358 -273.93519)
		(end 47.949358 -273.32813)
		(width 0.18288)
		(layer "In2.Cu")
		(net "M_B_CPU1_SA_CB<4>")
	)
	(segment
		(start 62.705488 -271.65935)
		(end 61.973206 -271.65935)
		(width 0.18288)
		(layer "In2.Cu")
		(net "M_B_CPU1_SA_CB<4>")
	)
	(segment
		(start 78.029308 -261.688326)
		(end 76.800202 -262.917432)
		(width 0.18288)
		(layer "In2.Cu")
		(net "M_B_CPU1_SA_CB<4>")
	)
	(segment
		(start 84.15401 -259.264912)
		(end 83.957668 -259.264912)
		(width 0.088646)
		(layer "In2.Cu")
		(net "M_B_CPU1_SA_CB<4>")
	)
	(segment
		(start 47.949358 -273.32813)
		(end 48.157638 -273.11985)
		(width 0.18288)
		(layer "In2.Cu")
		(net "M_B_CPU1_SA_CB<4>")
	)
	(segment
		(start 60.546996 -271.912588)
		(end 60.546996 -272.378932)
		(width 0.18288)
		(layer "In2.Cu")
		(net "M_B_CPU1_SA_CB<4>")
	)
	(segment
		(start 61.973206 -271.65935)
		(end 61.935868 -271.696688)
		(width 0.18288)
		(layer "In2.Cu")
		(net "M_B_CPU1_SA_CB<4>")
	)
	(segment
		(start 63.555626 -270.809212)
		(end 62.705488 -271.65935)
		(width 0.18288)
		(layer "In2.Cu")
		(net "M_B_CPU1_SA_CB<4>")
	)
	(segment
		(start 48.723042 -273.63674)
		(end 48.723042 -273.93519)
		(width 0.18288)
		(layer "In2.Cu")
		(net "M_B_CPU1_SA_CB<4>")
	)
	(segment
		(start 67.030092 -270.809212)
		(end 63.555626 -270.809212)
		(width 0.18288)
		(layer "In2.Cu")
		(net "M_B_CPU1_SA_CB<4>")
	)
	(segment
		(start 59.292744 -272.458434)
		(end 58.58002 -272.458434)
		(width 0.18288)
		(layer "In2.Cu")
		(net "M_B_CPU1_SA_CB<4>")
	)
	(segment
		(start 50.395378 -273.39163)
		(end 50.235358 -273.23161)
		(width 0.18288)
		(layer "In2.Cu")
		(net "M_B_CPU1_SA_CB<4>")
	)
	(segment
		(start 51.716178 -273.346418)
		(end 51.670966 -273.39163)
		(width 0.18288)
		(layer "In2.Cu")
		(net "M_B_CPU1_SA_CB<4>")
	)
	(segment
		(start 48.723042 -273.93519)
		(end 48.530002 -274.12823)
		(width 0.18288)
		(layer "In2.Cu")
		(net "M_B_CPU1_SA_CB<4>")
	)
	(segment
		(start 73.593706 -264.245598)
		(end 67.030092 -270.809212)
		(width 0.18288)
		(layer "In2.Cu")
		(net "M_B_CPU1_SA_CB<4>")
	)
	(segment
		(start 51.670966 -273.39163)
		(end 50.395378 -273.39163)
		(width 0.18288)
		(layer "In2.Cu")
		(net "M_B_CPU1_SA_CB<4>")
	)
	(segment
		(start 55.637938 -272.687542)
		(end 55.637938 -273.162522)
		(width 0.18288)
		(layer "In2.Cu")
		(net "M_B_CPU1_SA_CB<4>")
	)
	(segment
		(start 88.210644 -259.431282)
		(end 87.972392 -259.292598)
		(width 0.088646)
		(layer "In2.Cu")
		(net "M_B_CPU1_SA_CB<4>")
	)
	(segment
		(start 50.235358 -272.702782)
		(end 50.075338 -272.542762)
		(width 0.18288)
		(layer "In2.Cu")
		(net "M_B_CPU1_SA_CB<4>")
	)
	(segment
		(start 48.157638 -273.11985)
		(end 48.157638 -272.665444)
		(width 0.18288)
		(layer "In2.Cu")
		(net "M_B_CPU1_SA_CB<4>")
	)
	(segment
		(start 81.550256 -261.688326)
		(end 78.029308 -261.688326)
		(width 0.18288)
		(layer "In2.Cu")
		(net "M_B_CPU1_SA_CB<4>")
	)
	(segment
		(start 47.458884 -272.47215)
		(end 46.964346 -272.966688)
		(width 0.18288)
		(layer "In2.Cu")
		(net "M_B_CPU1_SA_CB<4>")
	)
	(segment
		(start 55.454042 -273.346418)
		(end 51.716178 -273.346418)
		(width 0.18288)
		(layer "In2.Cu")
		(net "M_B_CPU1_SA_CB<4>")
	)
	(segment
		(start 49.662842 -272.542762)
		(end 49.459388 -272.746216)
		(width 0.18288)
		(layer "In2.Cu")
		(net "M_B_CPU1_SA_CB<4>")
	)
	(segment
		(start 59.406282 -272.571972)
		(end 59.292744 -272.458434)
		(width 0.18288)
		(layer "In2.Cu")
		(net "M_B_CPU1_SA_CB<4>")
	)
	(segment
		(start 83.795362 -259.427218)
		(end 83.795362 -259.644642)
		(width 0.088646)
		(layer "In2.Cu")
		(net "M_B_CPU1_SA_CB<4>")
	)
	(segment
		(start 48.935386 -273.424396)
		(end 48.723042 -273.63674)
		(width 0.18288)
		(layer "In2.Cu")
		(net "M_B_CPU1_SA_CB<4>")
	)
	(segment
		(start 50.075338 -272.542762)
		(end 49.662842 -272.542762)
		(width 0.18288)
		(layer "In2.Cu")
		(net "M_B_CPU1_SA_CB<4>")
	)
	(segment
		(start 58.525664 -272.51279)
		(end 55.81269 -272.51279)
		(width 0.18288)
		(layer "In2.Cu")
		(net "M_B_CPU1_SA_CB<4>")
	)
	(segment
		(start 49.459388 -273.254724)
		(end 49.289716 -273.424396)
		(width 0.18288)
		(layer "In2.Cu")
		(net "M_B_CPU1_SA_CB<4>")
	)
	(segment
		(start 61.935868 -271.696688)
		(end 60.762896 -271.696688)
		(width 0.18288)
		(layer "In2.Cu")
		(net "M_B_CPU1_SA_CB<4>")
	)
	(segment
		(start 49.459388 -272.746216)
		(end 49.459388 -273.254724)
		(width 0.18288)
		(layer "In2.Cu")
		(net "M_B_CPU1_SA_CB<4>")
	)
	(segment
		(start 60.546996 -272.378932)
		(end 60.353956 -272.571972)
		(width 0.18288)
		(layer "In2.Cu")
		(net "M_B_CPU1_SA_CB<4>")
	)
	(segment
		(start 49.289716 -273.424396)
		(end 48.935386 -273.424396)
		(width 0.18288)
		(layer "In2.Cu")
		(net "M_B_CPU1_SA_CB<4>")
	)
	(segment
		(start 55.81269 -272.51279)
		(end 55.637938 -272.687542)
		(width 0.18288)
		(layer "In2.Cu")
		(net "M_B_CPU1_SA_CB<4>")
	)
	(segment
		(start 48.530002 -274.12823)
		(end 48.142398 -274.12823)
		(width 0.18288)
		(layer "In2.Cu")
		(net "M_B_CPU1_SA_CB<4>")
	)
	(segment
		(start 47.964344 -272.47215)
		(end 47.458884 -272.47215)
		(width 0.18288)
		(layer "In2.Cu")
		(net "M_B_CPU1_SA_CB<4>")
	)
	(segment
		(start 48.157638 -272.665444)
		(end 47.964344 -272.47215)
		(width 0.18288)
		(layer "In2.Cu")
		(net "M_B_CPU1_SA_CB<4>")
	)
	(segment
		(start 58.58002 -272.458434)
		(end 58.525664 -272.51279)
		(width 0.18288)
		(layer "In2.Cu")
		(net "M_B_CPU1_SA_CB<4>")
	)
	(segment
		(start 76.800202 -262.917432)
		(end 73.593706 -264.245598)
		(width 0.18288)
		(layer "In2.Cu")
		(net "M_B_CPU1_SA_CB<4>")
	)
	(segment
		(start 83.795362 -259.644642)
		(end 81.751678 -261.688326)
		(width 0.088646)
		(layer "In2.Cu")
		(net "M_B_CPU1_SA_CB<4>")
	)
	(segment
		(start 55.637938 -273.162522)
		(end 55.454042 -273.346418)
		(width 0.18288)
		(layer "In2.Cu")
		(net "M_B_CPU1_SA_CB<4>")
	)
	(segment
		(start 50.235358 -273.23161)
		(end 50.235358 -272.702782)
		(width 0.18288)
		(layer "In2.Cu")
		(net "M_B_CPU1_SA_CB<4>")
	)
	(segment
		(start 81.751678 -261.688326)
		(end 81.550256 -261.688326)
		(width 0.088646)
		(layer "In2.Cu")
		(net "M_B_CPU1_SA_CB<4>")
	)
	(segment
		(start 60.762896 -271.696688)
		(end 60.546996 -271.912588)
		(width 0.18288)
		(layer "In2.Cu")
		(net "M_B_CPU1_SA_CB<4>")
	)
	(segment
		(start 60.353956 -272.571972)
		(end 59.406282 -272.571972)
		(width 0.18288)
		(layer "In2.Cu")
		(net "M_B_CPU1_SA_CB<4>")
	)
	(segment
		(start 48.142398 -274.12823)
		(end 47.949358 -273.93519)
		(width 0.18288)
		(layer "In2.Cu")
		(net "M_B_CPU1_SA_CB<4>")
	)
	(arc
		(start 87.972392 -259.292598)
		(mid 87.785194 -259.242455)
		(end 87.597996 -259.292598)
		(width 0.088646)
		(layer "In2.Cu")
		(net "M_B_CPU1_SA_CB<4>")
	)
	(arc
		(start 85.152992 -259.292598)
		(mid 84.965794 -259.242455)
		(end 84.778596 -259.292598)
		(width 0.088646)
		(layer "In2.Cu")
		(net "M_B_CPU1_SA_CB<4>")
	)
	(arc
		(start 86.092792 -259.292598)
		(mid 85.905594 -259.242455)
		(end 85.718396 -259.292598)
		(width 0.088646)
		(layer "In2.Cu")
		(net "M_B_CPU1_SA_CB<4>")
	)
	(arc
		(start 85.718396 -259.292598)
		(mid 85.435694 -259.368374)
		(end 85.152992 -259.292598)
		(width 0.088646)
		(layer "In2.Cu")
		(net "M_B_CPU1_SA_CB<4>")
	)
	(arc
		(start 87.032592 -259.292598)
		(mid 86.845394 -259.242455)
		(end 86.658196 -259.292598)
		(width 0.088646)
		(layer "In2.Cu")
		(net "M_B_CPU1_SA_CB<4>")
	)
	(arc
		(start 87.597996 -259.292598)
		(mid 87.315294 -259.36834)
		(end 87.032592 -259.292598)
		(width 0.088646)
		(layer "In2.Cu")
		(net "M_B_CPU1_SA_CB<4>")
	)
	(arc
		(start 84.213192 -259.292598)
		(mid 84.18421 -259.277452)
		(end 84.15401 -259.264912)
		(width 0.088646)
		(layer "In2.Cu")
		(net "M_B_CPU1_SA_CB<4>")
	)
	(arc
		(start 86.658196 -259.292598)
		(mid 86.375494 -259.368374)
		(end 86.092792 -259.292598)
		(width 0.088646)
		(layer "In2.Cu")
		(net "M_B_CPU1_SA_CB<4>")
	)
	(arc
		(start 84.778596 -259.292598)
		(mid 84.495894 -259.368374)
		(end 84.213192 -259.292598)
		(width 0.088646)
		(layer "In2.Cu")
		(net "M_B_CPU1_SA_CB<4>")
	)
	(segment
		(start 51.089814 -276.366986)
		(end 51.08956 -276.366732)
		(width 0.20066)
		(layer "F.Cu")
		(net "M_B_CPU1_SA_CB<3>")
	)
	(segment
		(start 44.38142 -276.805898)
		(end 44.735242 -276.805898)
		(width 0.20066)
		(layer "F.Cu")
		(net "M_B_CPU1_SA_CB<3>")
	)
	(segment
		(start 44.735242 -276.805898)
		(end 44.749466 -276.791674)
		(width 0.101854)
		(layer "F.Cu")
		(net "M_B_CPU1_SA_CB<3>")
	)
	(segment
		(start 51.08956 -276.366732)
		(end 49.959514 -276.366732)
		(width 0.20066)
		(layer "F.Cu")
		(net "M_B_CPU1_SA_CB<3>")
	)
	(segment
		(start 90.604594 -260.709156)
		(end 90.604594 -261.244842)
		(width 0.20066)
		(layer "F.Cu")
		(net "M_B_CPU1_SA_CB<3>")
	)
	(segment
		(start 44.238926 -276.492716)
		(end 44.238926 -276.663404)
		(width 0.20066)
		(layer "F.Cu")
		(net "M_B_CPU1_SA_CB<3>")
	)
	(segment
		(start 90.604848 -260.708902)
		(end 90.604594 -260.709156)
		(width 0.20066)
		(layer "F.Cu")
		(net "M_B_CPU1_SA_CB<3>")
	)
	(segment
		(start 47.60468 -276.791674)
		(end 47.753778 -276.642576)
		(width 0.20066)
		(layer "F.Cu")
		(net "M_B_CPU1_SA_CB<3>")
	)
	(segment
		(start 47.882302 -276.362414)
		(end 48.277526 -276.362414)
		(width 0.20066)
		(layer "F.Cu")
		(net "M_B_CPU1_SA_CB<3>")
	)
	(segment
		(start 47.060358 -276.791674)
		(end 47.60468 -276.791674)
		(width 0.20066)
		(layer "F.Cu")
		(net "M_B_CPU1_SA_CB<3>")
	)
	(segment
		(start 48.277526 -276.362414)
		(end 48.489362 -276.57425)
		(width 0.20066)
		(layer "F.Cu")
		(net "M_B_CPU1_SA_CB<3>")
	)
	(segment
		(start 48.935894 -276.57425)
		(end 49.143412 -276.366732)
		(width 0.20066)
		(layer "F.Cu")
		(net "M_B_CPU1_SA_CB<3>")
	)
	(segment
		(start 49.143412 -276.366732)
		(end 49.959514 -276.366732)
		(width 0.20066)
		(layer "F.Cu")
		(net "M_B_CPU1_SA_CB<3>")
	)
	(segment
		(start 44.238926 -276.663404)
		(end 44.38142 -276.805898)
		(width 0.20066)
		(layer "F.Cu")
		(net "M_B_CPU1_SA_CB<3>")
	)
	(segment
		(start 44.749466 -276.791674)
		(end 44.987464 -276.791674)
		(width 0.101854)
		(layer "F.Cu")
		(net "M_B_CPU1_SA_CB<3>")
	)
	(segment
		(start 48.489362 -276.57425)
		(end 48.935894 -276.57425)
		(width 0.20066)
		(layer "F.Cu")
		(net "M_B_CPU1_SA_CB<3>")
	)
	(segment
		(start 47.753778 -276.642576)
		(end 47.753778 -276.490938)
		(width 0.20066)
		(layer "F.Cu")
		(net "M_B_CPU1_SA_CB<3>")
	)
	(segment
		(start 44.112942 -276.366732)
		(end 44.238926 -276.492716)
		(width 0.20066)
		(layer "F.Cu")
		(net "M_B_CPU1_SA_CB<3>")
	)
	(segment
		(start 42.415714 -276.366732)
		(end 44.112942 -276.366732)
		(width 0.20066)
		(layer "F.Cu")
		(net "M_B_CPU1_SA_CB<3>")
	)
	(segment
		(start 47.753778 -276.490938)
		(end 47.882302 -276.362414)
		(width 0.20066)
		(layer "F.Cu")
		(net "M_B_CPU1_SA_CB<3>")
	)
	(segment
		(start 44.987464 -276.791674)
		(end 47.060358 -276.791674)
		(width 0.1016)
		(layer "F.Cu")
		(net "M_B_CPU1_SA_CB<3>")
	)
	(segment
		(start 58.05805 -277.128224)
		(end 57.022238 -277.128224)
		(width 0.18288)
		(layer "In2.Cu")
		(net "M_B_CPU1_SA_CB<3>")
	)
	(segment
		(start 75.097386 -266.02309)
		(end 74.811382 -266.309094)
		(width 0.18288)
		(layer "In2.Cu")
		(net "M_B_CPU1_SA_CB<3>")
	)
	(segment
		(start 68.536312 -272.97126)
		(end 68.149216 -272.97126)
		(width 0.18288)
		(layer "In2.Cu")
		(net "M_B_CPU1_SA_CB<3>")
	)
	(segment
		(start 59.420506 -277.065232)
		(end 58.907426 -276.552152)
		(width 0.18288)
		(layer "In2.Cu")
		(net "M_B_CPU1_SA_CB<3>")
	)
	(segment
		(start 55.988966 -276.13483)
		(end 55.621682 -276.13483)
		(width 0.18288)
		(layer "In2.Cu")
		(net "M_B_CPU1_SA_CB<3>")
	)
	(segment
		(start 72.129904 -268.990572)
		(end 71.825866 -269.29461)
		(width 0.18288)
		(layer "In2.Cu")
		(net "M_B_CPU1_SA_CB<3>")
	)
	(segment
		(start 56.297068 -276.760432)
		(end 56.148986 -276.61235)
		(width 0.18288)
		(layer "In2.Cu")
		(net "M_B_CPU1_SA_CB<3>")
	)
	(segment
		(start 64.047878 -274.90293)
		(end 63.852806 -275.098002)
		(width 0.18288)
		(layer "In2.Cu")
		(net "M_B_CPU1_SA_CB<3>")
	)
	(segment
		(start 54.555136 -277.093426)
		(end 54.2798 -276.81809)
		(width 0.18288)
		(layer "In2.Cu")
		(net "M_B_CPU1_SA_CB<3>")
	)
	(segment
		(start 68.149216 -272.97126)
		(end 67.845178 -273.275298)
		(width 0.18288)
		(layer "In2.Cu")
		(net "M_B_CPU1_SA_CB<3>")
	)
	(segment
		(start 58.634122 -276.552152)
		(end 58.05805 -277.128224)
		(width 0.18288)
		(layer "In2.Cu")
		(net "M_B_CPU1_SA_CB<3>")
	)
	(segment
		(start 69.835522 -271.284954)
		(end 69.835522 -271.67205)
		(width 0.18288)
		(layer "In2.Cu")
		(net "M_B_CPU1_SA_CB<3>")
	)
	(segment
		(start 71.521828 -269.985744)
		(end 71.134732 -269.985744)
		(width 0.18288)
		(layer "In2.Cu")
		(net "M_B_CPU1_SA_CB<3>")
	)
	(segment
		(start 69.144388 -271.976088)
		(end 68.84035 -272.280126)
		(width 0.18288)
		(layer "In2.Cu")
		(net "M_B_CPU1_SA_CB<3>")
	)
	(segment
		(start 72.517 -268.990572)
		(end 72.129904 -268.990572)
		(width 0.18288)
		(layer "In2.Cu")
		(net "M_B_CPU1_SA_CB<3>")
	)
	(segment
		(start 58.907426 -276.552152)
		(end 58.634122 -276.552152)
		(width 0.18288)
		(layer "In2.Cu")
		(net "M_B_CPU1_SA_CB<3>")
	)
	(segment
		(start 67.154044 -273.966432)
		(end 66.853816 -274.26666)
		(width 0.18288)
		(layer "In2.Cu")
		(net "M_B_CPU1_SA_CB<3>")
	)
	(segment
		(start 88.304116 -260.994398)
		(end 88.263476 -261.015988)
		(width 0.088646)
		(layer "In2.Cu")
		(net "M_B_CPU1_SA_CB<3>")
	)
	(segment
		(start 79.434436 -263.364726)
		(end 77.963014 -264.836148)
		(width 0.18288)
		(layer "In2.Cu")
		(net "M_B_CPU1_SA_CB<3>")
	)
	(segment
		(start 87.986616 -261.561072)
		(end 87.972392 -261.5692)
		(width 0.088646)
		(layer "In2.Cu")
		(net "M_B_CPU1_SA_CB<3>")
	)
	(segment
		(start 63.324994 -276.181566)
		(end 63.324994 -276.46122)
		(width 0.18288)
		(layer "In2.Cu")
		(net "M_B_CPU1_SA_CB<3>")
	)
	(segment
		(start 63.39713 -275.098002)
		(end 63.169038 -275.326094)
		(width 0.18288)
		(layer "In2.Cu")
		(net "M_B_CPU1_SA_CB<3>")
	)
	(segment
		(start 73.125076 -267.9954)
		(end 72.821038 -268.299438)
		(width 0.18288)
		(layer "In2.Cu")
		(net "M_B_CPU1_SA_CB<3>")
	)
	(segment
		(start 64.047878 -274.4597)
		(end 64.047878 -274.90293)
		(width 0.18288)
		(layer "In2.Cu")
		(net "M_B_CPU1_SA_CB<3>")
	)
	(segment
		(start 71.825866 -269.29461)
		(end 71.825866 -269.681706)
		(width 0.18288)
		(layer "In2.Cu")
		(net "M_B_CPU1_SA_CB<3>")
	)
	(segment
		(start 70.13956 -270.980916)
		(end 69.835522 -271.284954)
		(width 0.18288)
		(layer "In2.Cu")
		(net "M_B_CPU1_SA_CB<3>")
	)
	(segment
		(start 59.840622 -277.065232)
		(end 59.420506 -277.065232)
		(width 0.18288)
		(layer "In2.Cu")
		(net "M_B_CPU1_SA_CB<3>")
	)
	(segment
		(start 90.604594 -261.244842)
		(end 90.60434 -261.245096)
		(width 0.088646)
		(layer "In2.Cu")
		(net "M_B_CPU1_SA_CB<3>")
	)
	(segment
		(start 61.876432 -276.84349)
		(end 60.062364 -276.84349)
		(width 0.18288)
		(layer "In2.Cu")
		(net "M_B_CPU1_SA_CB<3>")
	)
	(segment
		(start 73.81621 -267.304266)
		(end 73.81621 -267.691362)
		(width 0.18288)
		(layer "In2.Cu")
		(net "M_B_CPU1_SA_CB<3>")
	)
	(segment
		(start 60.062364 -276.84349)
		(end 59.840622 -277.065232)
		(width 0.18288)
		(layer "In2.Cu")
		(net "M_B_CPU1_SA_CB<3>")
	)
	(segment
		(start 68.84035 -272.667222)
		(end 68.536312 -272.97126)
		(width 0.18288)
		(layer "In2.Cu")
		(net "M_B_CPU1_SA_CB<3>")
	)
	(segment
		(start 74.811382 -266.69619)
		(end 74.507344 -267.000228)
		(width 0.18288)
		(layer "In2.Cu")
		(net "M_B_CPU1_SA_CB<3>")
	)
	(segment
		(start 64.240918 -274.26666)
		(end 64.047878 -274.4597)
		(width 0.18288)
		(layer "In2.Cu")
		(net "M_B_CPU1_SA_CB<3>")
	)
	(segment
		(start 63.169038 -275.326094)
		(end 63.169038 -276.02561)
		(width 0.18288)
		(layer "In2.Cu")
		(net "M_B_CPU1_SA_CB<3>")
	)
	(segment
		(start 74.120248 -267.000228)
		(end 73.81621 -267.304266)
		(width 0.18288)
		(layer "In2.Cu")
		(net "M_B_CPU1_SA_CB<3>")
	)
	(segment
		(start 71.825866 -269.681706)
		(end 71.521828 -269.985744)
		(width 0.18288)
		(layer "In2.Cu")
		(net "M_B_CPU1_SA_CB<3>")
	)
	(segment
		(start 67.54114 -273.966432)
		(end 67.154044 -273.966432)
		(width 0.18288)
		(layer "In2.Cu")
		(net "M_B_CPU1_SA_CB<3>")
	)
	(segment
		(start 55.268622 -277.093426)
		(end 54.555136 -277.093426)
		(width 0.18288)
		(layer "In2.Cu")
		(net "M_B_CPU1_SA_CB<3>")
	)
	(segment
		(start 52.358798 -277.003256)
		(end 51.726084 -277.003256)
		(width 0.18288)
		(layer "In2.Cu")
		(net "M_B_CPU1_SA_CB<3>")
	)
	(segment
		(start 52.543964 -276.81809)
		(end 52.358798 -277.003256)
		(width 0.18288)
		(layer "In2.Cu")
		(net "M_B_CPU1_SA_CB<3>")
	)
	(segment
		(start 55.621682 -276.13483)
		(end 55.428642 -276.32787)
		(width 0.18288)
		(layer "In2.Cu")
		(net "M_B_CPU1_SA_CB<3>")
	)
	(segment
		(start 71.134732 -269.985744)
		(end 70.830694 -270.289782)
		(width 0.18288)
		(layer "In2.Cu")
		(net "M_B_CPU1_SA_CB<3>")
	)
	(segment
		(start 74.811382 -266.309094)
		(end 74.811382 -266.69619)
		(width 0.18288)
		(layer "In2.Cu")
		(net "M_B_CPU1_SA_CB<3>")
	)
	(segment
		(start 69.531484 -271.976088)
		(end 69.144388 -271.976088)
		(width 0.18288)
		(layer "In2.Cu")
		(net "M_B_CPU1_SA_CB<3>")
	)
	(segment
		(start 73.512172 -267.9954)
		(end 73.125076 -267.9954)
		(width 0.18288)
		(layer "In2.Cu")
		(net "M_B_CPU1_SA_CB<3>")
	)
	(segment
		(start 55.428642 -276.32787)
		(end 55.428642 -276.933406)
		(width 0.18288)
		(layer "In2.Cu")
		(net "M_B_CPU1_SA_CB<3>")
	)
	(segment
		(start 68.84035 -272.280126)
		(end 68.84035 -272.667222)
		(width 0.18288)
		(layer "In2.Cu")
		(net "M_B_CPU1_SA_CB<3>")
	)
	(segment
		(start 70.526656 -270.980916)
		(end 70.13956 -270.980916)
		(width 0.18288)
		(layer "In2.Cu")
		(net "M_B_CPU1_SA_CB<3>")
	)
	(segment
		(start 63.324994 -276.46122)
		(end 62.686184 -277.10003)
		(width 0.18288)
		(layer "In2.Cu")
		(net "M_B_CPU1_SA_CB<3>")
	)
	(segment
		(start 57.022238 -277.128224)
		(end 56.654446 -276.760432)
		(width 0.18288)
		(layer "In2.Cu")
		(net "M_B_CPU1_SA_CB<3>")
	)
	(segment
		(start 69.835522 -271.67205)
		(end 69.531484 -271.976088)
		(width 0.18288)
		(layer "In2.Cu")
		(net "M_B_CPU1_SA_CB<3>")
	)
	(segment
		(start 74.507344 -267.000228)
		(end 74.120248 -267.000228)
		(width 0.18288)
		(layer "In2.Cu")
		(net "M_B_CPU1_SA_CB<3>")
	)
	(segment
		(start 54.2798 -276.81809)
		(end 52.543964 -276.81809)
		(width 0.18288)
		(layer "In2.Cu")
		(net "M_B_CPU1_SA_CB<3>")
	)
	(segment
		(start 72.821038 -268.686534)
		(end 72.517 -268.990572)
		(width 0.18288)
		(layer "In2.Cu")
		(net "M_B_CPU1_SA_CB<3>")
	)
	(segment
		(start 90.60434 -261.245096)
		(end 90.22715 -261.245096)
		(width 0.088646)
		(layer "In2.Cu")
		(net "M_B_CPU1_SA_CB<3>")
	)
	(segment
		(start 62.686184 -277.10003)
		(end 62.132972 -277.10003)
		(width 0.18288)
		(layer "In2.Cu")
		(net "M_B_CPU1_SA_CB<3>")
	)
	(segment
		(start 84.025994 -261.619746)
		(end 83.476084 -261.619746)
		(width 0.088646)
		(layer "In2.Cu")
		(net "M_B_CPU1_SA_CB<3>")
	)
	(segment
		(start 63.852806 -275.098002)
		(end 63.39713 -275.098002)
		(width 0.18288)
		(layer "In2.Cu")
		(net "M_B_CPU1_SA_CB<3>")
	)
	(segment
		(start 55.428642 -276.933406)
		(end 55.268622 -277.093426)
		(width 0.18288)
		(layer "In2.Cu")
		(net "M_B_CPU1_SA_CB<3>")
	)
	(segment
		(start 51.726084 -277.003256)
		(end 51.089814 -276.366986)
		(width 0.18288)
		(layer "In2.Cu")
		(net "M_B_CPU1_SA_CB<3>")
	)
	(segment
		(start 67.845178 -273.275298)
		(end 67.845178 -273.662394)
		(width 0.18288)
		(layer "In2.Cu")
		(net "M_B_CPU1_SA_CB<3>")
	)
	(segment
		(start 56.148986 -276.61235)
		(end 56.148986 -276.29485)
		(width 0.18288)
		(layer "In2.Cu")
		(net "M_B_CPU1_SA_CB<3>")
	)
	(segment
		(start 81.731104 -263.364726)
		(end 81.234788 -263.364726)
		(width 0.088646)
		(layer "In2.Cu")
		(net "M_B_CPU1_SA_CB<3>")
	)
	(segment
		(start 66.853816 -274.26666)
		(end 64.240918 -274.26666)
		(width 0.18288)
		(layer "In2.Cu")
		(net "M_B_CPU1_SA_CB<3>")
	)
	(segment
		(start 90.204798 -261.235952)
		(end 89.952068 -260.983222)
		(width 0.088646)
		(layer "In2.Cu")
		(net "M_B_CPU1_SA_CB<3>")
	)
	(segment
		(start 70.830694 -270.289782)
		(end 70.830694 -270.676878)
		(width 0.18288)
		(layer "In2.Cu")
		(net "M_B_CPU1_SA_CB<3>")
	)
	(segment
		(start 73.81621 -267.691362)
		(end 73.512172 -267.9954)
		(width 0.18288)
		(layer "In2.Cu")
		(net "M_B_CPU1_SA_CB<3>")
	)
	(segment
		(start 62.132972 -277.10003)
		(end 61.876432 -276.84349)
		(width 0.18288)
		(layer "In2.Cu")
		(net "M_B_CPU1_SA_CB<3>")
	)
	(segment
		(start 56.654446 -276.760432)
		(end 56.297068 -276.760432)
		(width 0.18288)
		(layer "In2.Cu")
		(net "M_B_CPU1_SA_CB<3>")
	)
	(segment
		(start 67.845178 -273.662394)
		(end 67.54114 -273.966432)
		(width 0.18288)
		(layer "In2.Cu")
		(net "M_B_CPU1_SA_CB<3>")
	)
	(segment
		(start 70.830694 -270.676878)
		(end 70.526656 -270.980916)
		(width 0.18288)
		(layer "In2.Cu")
		(net "M_B_CPU1_SA_CB<3>")
	)
	(segment
		(start 77.963014 -264.836148)
		(end 75.097386 -266.02309)
		(width 0.18288)
		(layer "In2.Cu")
		(net "M_B_CPU1_SA_CB<3>")
	)
	(segment
		(start 63.169038 -276.02561)
		(end 63.324994 -276.181566)
		(width 0.18288)
		(layer "In2.Cu")
		(net "M_B_CPU1_SA_CB<3>")
	)
	(segment
		(start 81.234788 -263.364726)
		(end 79.434436 -263.364726)
		(width 0.18288)
		(layer "In2.Cu")
		(net "M_B_CPU1_SA_CB<3>")
	)
	(segment
		(start 83.476084 -261.619746)
		(end 81.731104 -263.364726)
		(width 0.088646)
		(layer "In2.Cu")
		(net "M_B_CPU1_SA_CB<3>")
	)
	(segment
		(start 56.148986 -276.29485)
		(end 55.988966 -276.13483)
		(width 0.18288)
		(layer "In2.Cu")
		(net "M_B_CPU1_SA_CB<3>")
	)
	(segment
		(start 72.821038 -268.299438)
		(end 72.821038 -268.686534)
		(width 0.18288)
		(layer "In2.Cu")
		(net "M_B_CPU1_SA_CB<3>")
	)
	(arc
		(start 86.658196 -261.5692)
		(mid 86.375494 -261.493424)
		(end 86.092792 -261.5692)
		(width 0.088646)
		(layer "In2.Cu")
		(net "M_B_CPU1_SA_CB<3>")
	)
	(arc
		(start 88.978994 -260.947662)
		(mid 88.937687 -260.931683)
		(end 88.897714 -260.91261)
		(width 0.088646)
		(layer "In2.Cu")
		(net "M_B_CPU1_SA_CB<3>")
	)
	(arc
		(start 88.537796 -260.920738)
		(mid 88.424989 -260.970353)
		(end 88.304116 -260.994398)
		(width 0.088646)
		(layer "In2.Cu")
		(net "M_B_CPU1_SA_CB<3>")
	)
	(arc
		(start 88.159844 -261.245096)
		(mid 88.113705 -261.425281)
		(end 87.986616 -261.561072)
		(width 0.088646)
		(layer "In2.Cu")
		(net "M_B_CPU1_SA_CB<3>")
	)
	(arc
		(start 88.897714 -260.91261)
		(mid 88.716725 -260.870638)
		(end 88.537796 -260.920738)
		(width 0.088646)
		(layer "In2.Cu")
		(net "M_B_CPU1_SA_CB<3>")
	)
	(arc
		(start 87.597996 -261.5692)
		(mid 87.315294 -261.493424)
		(end 87.032592 -261.5692)
		(width 0.088646)
		(layer "In2.Cu")
		(net "M_B_CPU1_SA_CB<3>")
	)
	(arc
		(start 87.972392 -261.5692)
		(mid 87.785194 -261.619377)
		(end 87.597996 -261.5692)
		(width 0.088646)
		(layer "In2.Cu")
		(net "M_B_CPU1_SA_CB<3>")
	)
	(arc
		(start 89.492328 -260.912356)
		(mid 89.452359 -260.931437)
		(end 89.411048 -260.947408)
		(width 0.088646)
		(layer "In2.Cu")
		(net "M_B_CPU1_SA_CB<3>")
	)
	(arc
		(start 90.22715 -261.245096)
		(mid 90.215097 -261.242699)
		(end 90.204798 -261.235952)
		(width 0.088646)
		(layer "In2.Cu")
		(net "M_B_CPU1_SA_CB<3>")
	)
	(arc
		(start 89.952068 -260.983222)
		(mid 89.733806 -260.872527)
		(end 89.492328 -260.912356)
		(width 0.088646)
		(layer "In2.Cu")
		(net "M_B_CPU1_SA_CB<3>")
	)
	(arc
		(start 87.032592 -261.5692)
		(mid 86.845394 -261.619377)
		(end 86.658196 -261.5692)
		(width 0.088646)
		(layer "In2.Cu")
		(net "M_B_CPU1_SA_CB<3>")
	)
	(arc
		(start 84.213192 -261.5692)
		(mid 84.122916 -261.606774)
		(end 84.025994 -261.619746)
		(width 0.088646)
		(layer "In2.Cu")
		(net "M_B_CPU1_SA_CB<3>")
	)
	(arc
		(start 84.778596 -261.5692)
		(mid 84.495894 -261.493424)
		(end 84.213192 -261.5692)
		(width 0.088646)
		(layer "In2.Cu")
		(net "M_B_CPU1_SA_CB<3>")
	)
	(arc
		(start 85.718396 -261.5692)
		(mid 85.435694 -261.493424)
		(end 85.152992 -261.5692)
		(width 0.088646)
		(layer "In2.Cu")
		(net "M_B_CPU1_SA_CB<3>")
	)
	(arc
		(start 89.411048 -260.947408)
		(mid 89.195042 -260.983136)
		(end 88.978994 -260.947662)
		(width 0.088646)
		(layer "In2.Cu")
		(net "M_B_CPU1_SA_CB<3>")
	)
	(arc
		(start 88.263476 -261.015988)
		(mid 88.186953 -261.119367)
		(end 88.159844 -261.245096)
		(width 0.088646)
		(layer "In2.Cu")
		(net "M_B_CPU1_SA_CB<3>")
	)
	(arc
		(start 85.152992 -261.5692)
		(mid 84.965794 -261.619343)
		(end 84.778596 -261.5692)
		(width 0.088646)
		(layer "In2.Cu")
		(net "M_B_CPU1_SA_CB<3>")
	)
	(arc
		(start 86.092792 -261.5692)
		(mid 85.905594 -261.619377)
		(end 85.718396 -261.5692)
		(width 0.088646)
		(layer "In2.Cu")
		(net "M_B_CPU1_SA_CB<3>")
	)
	(segment
		(start 48.64481 -278.066754)
		(end 49.959514 -278.066754)
		(width 0.20066)
		(layer "F.Cu")
		(net "M_B_CPU1_SA_CB<2>")
	)
	(segment
		(start 48.004476 -278.27859)
		(end 48.432974 -278.27859)
		(width 0.20066)
		(layer "F.Cu")
		(net "M_B_CPU1_SA_CB<2>")
	)
	(segment
		(start 48.432974 -278.27859)
		(end 48.64481 -278.066754)
		(width 0.20066)
		(layer "F.Cu")
		(net "M_B_CPU1_SA_CB<2>")
	)
	(segment
		(start 51.089814 -278.067008)
		(end 51.08956 -278.066754)
		(width 0.20066)
		(layer "F.Cu")
		(net "M_B_CPU1_SA_CB<2>")
	)
	(segment
		(start 43.99788 -277.631652)
		(end 44.735242 -277.631652)
		(width 0.20066)
		(layer "F.Cu")
		(net "M_B_CPU1_SA_CB<2>")
	)
	(segment
		(start 47.693326 -277.641812)
		(end 47.83709 -277.785576)
		(width 0.20066)
		(layer "F.Cu")
		(net "M_B_CPU1_SA_CB<2>")
	)
	(segment
		(start 47.060358 -277.641812)
		(end 47.693326 -277.641812)
		(width 0.20066)
		(layer "F.Cu")
		(net "M_B_CPU1_SA_CB<2>")
	)
	(segment
		(start 90.134694 -261.522718)
		(end 90.134694 -262.058658)
		(width 0.20066)
		(layer "F.Cu")
		(net "M_B_CPU1_SA_CB<2>")
	)
	(segment
		(start 44.745402 -277.641812)
		(end 45.000418 -277.641812)
		(width 0.101854)
		(layer "F.Cu")
		(net "M_B_CPU1_SA_CB<2>")
	)
	(segment
		(start 45.000418 -277.641812)
		(end 47.060358 -277.641812)
		(width 0.1016)
		(layer "F.Cu")
		(net "M_B_CPU1_SA_CB<2>")
	)
	(segment
		(start 43.562778 -278.066754)
		(end 43.99788 -277.631652)
		(width 0.20066)
		(layer "F.Cu")
		(net "M_B_CPU1_SA_CB<2>")
	)
	(segment
		(start 47.83709 -277.785576)
		(end 47.83709 -278.111204)
		(width 0.20066)
		(layer "F.Cu")
		(net "M_B_CPU1_SA_CB<2>")
	)
	(segment
		(start 47.83709 -278.111204)
		(end 48.004476 -278.27859)
		(width 0.20066)
		(layer "F.Cu")
		(net "M_B_CPU1_SA_CB<2>")
	)
	(segment
		(start 51.08956 -278.066754)
		(end 49.959514 -278.066754)
		(width 0.20066)
		(layer "F.Cu")
		(net "M_B_CPU1_SA_CB<2>")
	)
	(segment
		(start 44.735242 -277.631652)
		(end 44.745402 -277.641812)
		(width 0.101854)
		(layer "F.Cu")
		(net "M_B_CPU1_SA_CB<2>")
	)
	(segment
		(start 42.415714 -278.066754)
		(end 43.562778 -278.066754)
		(width 0.20066)
		(layer "F.Cu")
		(net "M_B_CPU1_SA_CB<2>")
	)
	(segment
		(start 55.067454 -279.691592)
		(end 54.874414 -279.498552)
		(width 0.18288)
		(layer "In2.Cu")
		(net "M_B_CPU1_SA_CB<2>")
	)
	(segment
		(start 56.530494 -278.44496)
		(end 55.790592 -278.44496)
		(width 0.18288)
		(layer "In2.Cu")
		(net "M_B_CPU1_SA_CB<2>")
	)
	(segment
		(start 61.400182 -278.122126)
		(end 60.42533 -278.122126)
		(width 0.18288)
		(layer "In2.Cu")
		(net "M_B_CPU1_SA_CB<2>")
	)
	(segment
		(start 56.930544 -278.84501)
		(end 56.530494 -278.44496)
		(width 0.18288)
		(layer "In2.Cu")
		(net "M_B_CPU1_SA_CB<2>")
	)
	(segment
		(start 89.483692 -261.572756)
		(end 89.477596 -261.5692)
		(width 0.088646)
		(layer "In2.Cu")
		(net "M_B_CPU1_SA_CB<2>")
	)
	(segment
		(start 76.333858 -266.6111)
		(end 67.454526 -275.490432)
		(width 0.18288)
		(layer "In2.Cu")
		(net "M_B_CPU1_SA_CB<2>")
	)
	(segment
		(start 54.29631 -278.56307)
		(end 54.031642 -278.298402)
		(width 0.18288)
		(layer "In2.Cu")
		(net "M_B_CPU1_SA_CB<2>")
	)
	(segment
		(start 66.155062 -276.789896)
		(end 65.757298 -276.789896)
		(width 0.18288)
		(layer "In2.Cu")
		(net "M_B_CPU1_SA_CB<2>")
	)
	(segment
		(start 65.191386 -277.082504)
		(end 64.898778 -276.789896)
		(width 0.18288)
		(layer "In2.Cu")
		(net "M_B_CPU1_SA_CB<2>")
	)
	(segment
		(start 52.537868 -278.495506)
		(end 52.537868 -279.118314)
		(width 0.18288)
		(layer "In2.Cu")
		(net "M_B_CPU1_SA_CB<2>")
	)
	(segment
		(start 78.57871 -265.681206)
		(end 76.333858 -266.6111)
		(width 0.18288)
		(layer "In2.Cu")
		(net "M_B_CPU1_SA_CB<2>")
	)
	(segment
		(start 60.42533 -278.122126)
		(end 59.725306 -278.82215)
		(width 0.18288)
		(layer "In2.Cu")
		(net "M_B_CPU1_SA_CB<2>")
	)
	(segment
		(start 88.451182 -262.377936)
		(end 88.442292 -262.383016)
		(width 0.088646)
		(layer "In2.Cu")
		(net "M_B_CPU1_SA_CB<2>")
	)
	(segment
		(start 55.577994 -279.483312)
		(end 55.369714 -279.691592)
		(width 0.18288)
		(layer "In2.Cu")
		(net "M_B_CPU1_SA_CB<2>")
	)
	(segment
		(start 89.477596 -261.5692)
		(end 89.462864 -261.560564)
		(width 0.088646)
		(layer "In2.Cu")
		(net "M_B_CPU1_SA_CB<2>")
	)
	(segment
		(start 67.070224 -275.378926)
		(end 66.797428 -275.378926)
		(width 0.18288)
		(layer "In2.Cu")
		(net "M_B_CPU1_SA_CB<2>")
	)
	(segment
		(start 51.634898 -278.26081)
		(end 51.283616 -278.26081)
		(width 0.18288)
		(layer "In2.Cu")
		(net "M_B_CPU1_SA_CB<2>")
	)
	(segment
		(start 59.081924 -278.467312)
		(end 58.37555 -278.467312)
		(width 0.18288)
		(layer "In2.Cu")
		(net "M_B_CPU1_SA_CB<2>")
	)
	(segment
		(start 52.38115 -279.275032)
		(end 52.036726 -279.275032)
		(width 0.18288)
		(layer "In2.Cu")
		(net "M_B_CPU1_SA_CB<2>")
	)
	(segment
		(start 64.377062 -277.443438)
		(end 64.028066 -277.792434)
		(width 0.18288)
		(layer "In2.Cu")
		(net "M_B_CPU1_SA_CB<2>")
	)
	(segment
		(start 67.454526 -275.490432)
		(end 67.18173 -275.490432)
		(width 0.18288)
		(layer "In2.Cu")
		(net "M_B_CPU1_SA_CB<2>")
	)
	(segment
		(start 66.797428 -275.378926)
		(end 66.572638 -275.603716)
		(width 0.18288)
		(layer "In2.Cu")
		(net "M_B_CPU1_SA_CB<2>")
	)
	(segment
		(start 52.036726 -279.275032)
		(end 51.827938 -279.066244)
		(width 0.18288)
		(layer "In2.Cu")
		(net "M_B_CPU1_SA_CB<2>")
	)
	(segment
		(start 51.827938 -278.45385)
		(end 51.634898 -278.26081)
		(width 0.18288)
		(layer "In2.Cu")
		(net "M_B_CPU1_SA_CB<2>")
	)
	(segment
		(start 83.687158 -262.307324)
		(end 82.422492 -263.57199)
		(width 0.088646)
		(layer "In2.Cu")
		(net "M_B_CPU1_SA_CB<2>")
	)
	(segment
		(start 52.734972 -278.298402)
		(end 52.537868 -278.495506)
		(width 0.18288)
		(layer "In2.Cu")
		(net "M_B_CPU1_SA_CB<2>")
	)
	(segment
		(start 89.82202 -262.058658)
		(end 89.756488 -261.993126)
		(width 0.088646)
		(layer "In2.Cu")
		(net "M_B_CPU1_SA_CB<2>")
	)
	(segment
		(start 54.661816 -278.56307)
		(end 54.29631 -278.56307)
		(width 0.18288)
		(layer "In2.Cu")
		(net "M_B_CPU1_SA_CB<2>")
	)
	(segment
		(start 59.436762 -278.82215)
		(end 59.081924 -278.467312)
		(width 0.18288)
		(layer "In2.Cu")
		(net "M_B_CPU1_SA_CB<2>")
	)
	(segment
		(start 82.422492 -263.57199)
		(end 82.312764 -263.57199)
		(width 0.088646)
		(layer "In2.Cu")
		(net "M_B_CPU1_SA_CB<2>")
	)
	(segment
		(start 51.827938 -279.066244)
		(end 51.827938 -278.45385)
		(width 0.18288)
		(layer "In2.Cu")
		(net "M_B_CPU1_SA_CB<2>")
	)
	(segment
		(start 84.025994 -262.307324)
		(end 83.687158 -262.307324)
		(width 0.088646)
		(layer "In2.Cu")
		(net "M_B_CPU1_SA_CB<2>")
	)
	(segment
		(start 81.234788 -264.055606)
		(end 80.20431 -264.055606)
		(width 0.18288)
		(layer "In2.Cu")
		(net "M_B_CPU1_SA_CB<2>")
	)
	(segment
		(start 81.829148 -264.055606)
		(end 81.234788 -264.055606)
		(width 0.088646)
		(layer "In2.Cu")
		(net "M_B_CPU1_SA_CB<2>")
	)
	(segment
		(start 88.912192 -261.5692)
		(end 88.906096 -261.572756)
		(width 0.088646)
		(layer "In2.Cu")
		(net "M_B_CPU1_SA_CB<2>")
	)
	(segment
		(start 67.18173 -275.490432)
		(end 67.070224 -275.378926)
		(width 0.18288)
		(layer "In2.Cu")
		(net "M_B_CPU1_SA_CB<2>")
	)
	(segment
		(start 61.793628 -278.515572)
		(end 61.400182 -278.122126)
		(width 0.18288)
		(layer "In2.Cu")
		(net "M_B_CPU1_SA_CB<2>")
	)
	(segment
		(start 55.790592 -278.44496)
		(end 55.577994 -278.657558)
		(width 0.18288)
		(layer "In2.Cu")
		(net "M_B_CPU1_SA_CB<2>")
	)
	(segment
		(start 64.028066 -277.792434)
		(end 62.28334 -278.515572)
		(width 0.18288)
		(layer "In2.Cu")
		(net "M_B_CPU1_SA_CB<2>")
	)
	(segment
		(start 66.572638 -275.603716)
		(end 66.572638 -275.876512)
		(width 0.18288)
		(layer "In2.Cu")
		(net "M_B_CPU1_SA_CB<2>")
	)
	(segment
		(start 82.312764 -263.57199)
		(end 81.829148 -264.055606)
		(width 0.088646)
		(layer "In2.Cu")
		(net "M_B_CPU1_SA_CB<2>")
	)
	(segment
		(start 54.031642 -278.298402)
		(end 52.734972 -278.298402)
		(width 0.18288)
		(layer "In2.Cu")
		(net "M_B_CPU1_SA_CB<2>")
	)
	(segment
		(start 58.37555 -278.467312)
		(end 57.997852 -278.84501)
		(width 0.18288)
		(layer "In2.Cu")
		(net "M_B_CPU1_SA_CB<2>")
	)
	(segment
		(start 64.377062 -277.02637)
		(end 64.377062 -277.443438)
		(width 0.18288)
		(layer "In2.Cu")
		(net "M_B_CPU1_SA_CB<2>")
	)
	(segment
		(start 90.134694 -262.058658)
		(end 89.82202 -262.058658)
		(width 0.088646)
		(layer "In2.Cu")
		(net "M_B_CPU1_SA_CB<2>")
	)
	(segment
		(start 52.537868 -279.118314)
		(end 52.38115 -279.275032)
		(width 0.18288)
		(layer "In2.Cu")
		(net "M_B_CPU1_SA_CB<2>")
	)
	(segment
		(start 54.874414 -279.498552)
		(end 54.874414 -278.775668)
		(width 0.18288)
		(layer "In2.Cu")
		(net "M_B_CPU1_SA_CB<2>")
	)
	(segment
		(start 55.369714 -279.691592)
		(end 55.067454 -279.691592)
		(width 0.18288)
		(layer "In2.Cu")
		(net "M_B_CPU1_SA_CB<2>")
	)
	(segment
		(start 65.757298 -276.789896)
		(end 65.46469 -277.082504)
		(width 0.18288)
		(layer "In2.Cu")
		(net "M_B_CPU1_SA_CB<2>")
	)
	(segment
		(start 54.874414 -278.775668)
		(end 54.661816 -278.56307)
		(width 0.18288)
		(layer "In2.Cu")
		(net "M_B_CPU1_SA_CB<2>")
	)
	(segment
		(start 55.577994 -278.657558)
		(end 55.577994 -279.483312)
		(width 0.18288)
		(layer "In2.Cu")
		(net "M_B_CPU1_SA_CB<2>")
	)
	(segment
		(start 80.20431 -264.055606)
		(end 78.57871 -265.681206)
		(width 0.18288)
		(layer "In2.Cu")
		(net "M_B_CPU1_SA_CB<2>")
	)
	(segment
		(start 57.997852 -278.84501)
		(end 56.930544 -278.84501)
		(width 0.18288)
		(layer "In2.Cu")
		(net "M_B_CPU1_SA_CB<2>")
	)
	(segment
		(start 59.725306 -278.82215)
		(end 59.436762 -278.82215)
		(width 0.18288)
		(layer "In2.Cu")
		(net "M_B_CPU1_SA_CB<2>")
	)
	(segment
		(start 64.898778 -276.789896)
		(end 64.613536 -276.789896)
		(width 0.18288)
		(layer "In2.Cu")
		(net "M_B_CPU1_SA_CB<2>")
	)
	(segment
		(start 62.28334 -278.515572)
		(end 61.793628 -278.515572)
		(width 0.18288)
		(layer "In2.Cu")
		(net "M_B_CPU1_SA_CB<2>")
	)
	(segment
		(start 66.684144 -276.260814)
		(end 66.155062 -276.789896)
		(width 0.18288)
		(layer "In2.Cu")
		(net "M_B_CPU1_SA_CB<2>")
	)
	(segment
		(start 66.684144 -275.988018)
		(end 66.684144 -276.260814)
		(width 0.18288)
		(layer "In2.Cu")
		(net "M_B_CPU1_SA_CB<2>")
	)
	(segment
		(start 65.46469 -277.082504)
		(end 65.191386 -277.082504)
		(width 0.18288)
		(layer "In2.Cu")
		(net "M_B_CPU1_SA_CB<2>")
	)
	(segment
		(start 64.613536 -276.789896)
		(end 64.377062 -277.02637)
		(width 0.18288)
		(layer "In2.Cu")
		(net "M_B_CPU1_SA_CB<2>")
	)
	(segment
		(start 66.572638 -275.876512)
		(end 66.684144 -275.988018)
		(width 0.18288)
		(layer "In2.Cu")
		(net "M_B_CPU1_SA_CB<2>")
	)
	(segment
		(start 51.283616 -278.26081)
		(end 51.089814 -278.067008)
		(width 0.18288)
		(layer "In2.Cu")
		(net "M_B_CPU1_SA_CB<2>")
	)
	(arc
		(start 85.248496 -262.383016)
		(mid 84.965794 -262.30724)
		(end 84.683092 -262.383016)
		(width 0.088646)
		(layer "In2.Cu")
		(net "M_B_CPU1_SA_CB<2>")
	)
	(arc
		(start 86.562692 -262.383016)
		(mid 86.375494 -262.433159)
		(end 86.188296 -262.383016)
		(width 0.088646)
		(layer "In2.Cu")
		(net "M_B_CPU1_SA_CB<2>")
	)
	(arc
		(start 87.128096 -262.383016)
		(mid 86.845394 -262.30724)
		(end 86.562692 -262.383016)
		(width 0.088646)
		(layer "In2.Cu")
		(net "M_B_CPU1_SA_CB<2>")
	)
	(arc
		(start 88.906096 -261.572756)
		(mid 88.703683 -261.779169)
		(end 88.629744 -262.058658)
		(width 0.088646)
		(layer "In2.Cu")
		(net "M_B_CPU1_SA_CB<2>")
	)
	(arc
		(start 88.629744 -262.058658)
		(mid 88.582065 -262.241558)
		(end 88.451182 -262.377936)
		(width 0.088646)
		(layer "In2.Cu")
		(net "M_B_CPU1_SA_CB<2>")
	)
	(arc
		(start 86.188296 -262.383016)
		(mid 85.905594 -262.30724)
		(end 85.622892 -262.383016)
		(width 0.088646)
		(layer "In2.Cu")
		(net "M_B_CPU1_SA_CB<2>")
	)
	(arc
		(start 87.502492 -262.383016)
		(mid 87.315294 -262.433159)
		(end 87.128096 -262.383016)
		(width 0.088646)
		(layer "In2.Cu")
		(net "M_B_CPU1_SA_CB<2>")
	)
	(arc
		(start 89.756488 -261.993126)
		(mid 89.669244 -261.751038)
		(end 89.483692 -261.572756)
		(width 0.088646)
		(layer "In2.Cu")
		(net "M_B_CPU1_SA_CB<2>")
	)
	(arc
		(start 89.462864 -261.560564)
		(mid 89.186389 -261.493244)
		(end 88.912192 -261.5692)
		(width 0.088646)
		(layer "In2.Cu")
		(net "M_B_CPU1_SA_CB<2>")
	)
	(arc
		(start 85.622892 -262.383016)
		(mid 85.435694 -262.433159)
		(end 85.248496 -262.383016)
		(width 0.088646)
		(layer "In2.Cu")
		(net "M_B_CPU1_SA_CB<2>")
	)
	(arc
		(start 84.308696 -262.383016)
		(mid 84.17233 -262.326538)
		(end 84.025994 -262.307324)
		(width 0.088646)
		(layer "In2.Cu")
		(net "M_B_CPU1_SA_CB<2>")
	)
	(arc
		(start 84.683092 -262.383016)
		(mid 84.495894 -262.433159)
		(end 84.308696 -262.383016)
		(width 0.088646)
		(layer "In2.Cu")
		(net "M_B_CPU1_SA_CB<2>")
	)
	(arc
		(start 88.442292 -262.383016)
		(mid 88.255094 -262.433159)
		(end 88.067896 -262.383016)
		(width 0.088646)
		(layer "In2.Cu")
		(net "M_B_CPU1_SA_CB<2>")
	)
	(arc
		(start 88.067896 -262.383016)
		(mid 87.785194 -262.30724)
		(end 87.502492 -262.383016)
		(width 0.088646)
		(layer "In2.Cu")
		(net "M_B_CPU1_SA_CB<2>")
	)
	(segment
		(start 40.36568 -277.427944)
		(end 39.861236 -277.427944)
		(width 0.20066)
		(layer "F.Cu")
		(net "M_B_CPU1_SA_CB<1>")
	)
	(segment
		(start 88.724994 -261.244588)
		(end 88.724994 -261.244842)
		(width 0.20066)
		(layer "F.Cu")
		(net "M_B_CPU1_SA_CB<1>")
	)
	(segment
		(start 40.520112 -276.945344)
		(end 40.520112 -277.273512)
		(width 0.20066)
		(layer "F.Cu")
		(net "M_B_CPU1_SA_CB<1>")
	)
	(segment
		(start 46.964346 -277.216616)
		(end 45.859446 -277.216616)
		(width 0.20066)
		(layer "F.Cu")
		(net "M_B_CPU1_SA_CB<1>")
	)
	(segment
		(start 88.725248 -261.244334)
		(end 88.724994 -261.244588)
		(width 0.20066)
		(layer "F.Cu")
		(net "M_B_CPU1_SA_CB<1>")
	)
	(segment
		(start 41.3004 -276.791674)
		(end 41.29151 -276.782784)
		(width 0.1016)
		(layer "F.Cu")
		(net "M_B_CPU1_SA_CB<1>")
	)
	(segment
		(start 39.649908 -277.216616)
		(end 38.315646 -277.216616)
		(width 0.20066)
		(layer "F.Cu")
		(net "M_B_CPU1_SA_CB<1>")
	)
	(segment
		(start 45.859446 -277.216616)
		(end 44.22013 -277.216616)
		(width 0.20066)
		(layer "F.Cu")
		(net "M_B_CPU1_SA_CB<1>")
	)
	(segment
		(start 44.22013 -277.216616)
		(end 43.795188 -276.791674)
		(width 0.20066)
		(layer "F.Cu")
		(net "M_B_CPU1_SA_CB<1>")
	)
	(segment
		(start 88.725248 -260.708902)
		(end 88.725248 -261.244334)
		(width 0.20066)
		(layer "F.Cu")
		(net "M_B_CPU1_SA_CB<1>")
	)
	(segment
		(start 43.795188 -276.791674)
		(end 43.616626 -276.791674)
		(width 0.20066)
		(layer "F.Cu")
		(net "M_B_CPU1_SA_CB<1>")
	)
	(segment
		(start 43.616626 -276.791674)
		(end 43.285918 -276.791674)
		(width 0.101854)
		(layer "F.Cu")
		(net "M_B_CPU1_SA_CB<1>")
	)
	(segment
		(start 40.682672 -276.782784)
		(end 40.520112 -276.945344)
		(width 0.20066)
		(layer "F.Cu")
		(net "M_B_CPU1_SA_CB<1>")
	)
	(segment
		(start 39.861236 -277.427944)
		(end 39.649908 -277.216616)
		(width 0.20066)
		(layer "F.Cu")
		(net "M_B_CPU1_SA_CB<1>")
	)
	(segment
		(start 40.520112 -277.273512)
		(end 40.36568 -277.427944)
		(width 0.20066)
		(layer "F.Cu")
		(net "M_B_CPU1_SA_CB<1>")
	)
	(segment
		(start 43.285918 -276.791674)
		(end 41.3004 -276.791674)
		(width 0.1016)
		(layer "F.Cu")
		(net "M_B_CPU1_SA_CB<1>")
	)
	(segment
		(start 41.29151 -276.782784)
		(end 40.682672 -276.782784)
		(width 0.20066)
		(layer "F.Cu")
		(net "M_B_CPU1_SA_CB<1>")
	)
	(segment
		(start 84.025994 -261.809992)
		(end 83.727798 -261.809992)
		(width 0.088646)
		(layer "In2.Cu")
		(net "M_B_CPU1_SA_CB<1>")
	)
	(segment
		(start 52.700682 -277.753572)
		(end 52.460906 -277.513796)
		(width 0.18288)
		(layer "In2.Cu")
		(net "M_B_CPU1_SA_CB<1>")
	)
	(segment
		(start 47.64278 -277.216616)
		(end 46.964346 -277.216616)
		(width 0.18288)
		(layer "In2.Cu")
		(net "M_B_CPU1_SA_CB<1>")
	)
	(segment
		(start 76.046076 -266.180316)
		(end 67.451732 -274.77466)
		(width 0.18288)
		(layer "In2.Cu")
		(net "M_B_CPU1_SA_CB<1>")
	)
	(segment
		(start 64.560704 -275.622258)
		(end 63.941198 -276.241764)
		(width 0.18288)
		(layer "In2.Cu")
		(net "M_B_CPU1_SA_CB<1>")
	)
	(segment
		(start 55.018432 -277.627334)
		(end 54.26329 -277.627334)
		(width 0.18288)
		(layer "In2.Cu")
		(net "M_B_CPU1_SA_CB<1>")
	)
	(segment
		(start 50.388012 -277.450042)
		(end 50.388012 -277.18766)
		(width 0.18288)
		(layer "In2.Cu")
		(net "M_B_CPU1_SA_CB<1>")
	)
	(segment
		(start 66.179192 -274.77466)
		(end 65.331594 -275.622258)
		(width 0.18288)
		(layer "In2.Cu")
		(net "M_B_CPU1_SA_CB<1>")
	)
	(segment
		(start 48.50765 -278.517096)
		(end 48.006 -278.517096)
		(width 0.18288)
		(layer "In2.Cu")
		(net "M_B_CPU1_SA_CB<1>")
	)
	(segment
		(start 62.939676 -277.614126)
		(end 59.470544 -277.614126)
		(width 0.18288)
		(layer "In2.Cu")
		(net "M_B_CPU1_SA_CB<1>")
	)
	(segment
		(start 50.579782 -277.641812)
		(end 50.388012 -277.450042)
		(width 0.18288)
		(layer "In2.Cu")
		(net "M_B_CPU1_SA_CB<1>")
	)
	(segment
		(start 88.724994 -261.244842)
		(end 88.229694 -261.594092)
		(width 0.088646)
		(layer "In2.Cu")
		(net "M_B_CPU1_SA_CB<1>")
	)
	(segment
		(start 56.465978 -277.638002)
		(end 56.16702 -277.93696)
		(width 0.18288)
		(layer "In2.Cu")
		(net "M_B_CPU1_SA_CB<1>")
	)
	(segment
		(start 49.546256 -277.495254)
		(end 49.370234 -277.671276)
		(width 0.18288)
		(layer "In2.Cu")
		(net "M_B_CPU1_SA_CB<1>")
	)
	(segment
		(start 81.753202 -263.710166)
		(end 81.234788 -263.710166)
		(width 0.088646)
		(layer "In2.Cu")
		(net "M_B_CPU1_SA_CB<1>")
	)
	(segment
		(start 59.125358 -277.959312)
		(end 58.699908 -277.959312)
		(width 0.18288)
		(layer "In2.Cu")
		(net "M_B_CPU1_SA_CB<1>")
	)
	(segment
		(start 49.370234 -277.671276)
		(end 48.925988 -277.671276)
		(width 0.18288)
		(layer "In2.Cu")
		(net "M_B_CPU1_SA_CB<1>")
	)
	(segment
		(start 56.16702 -277.93696)
		(end 55.328058 -277.93696)
		(width 0.18288)
		(layer "In2.Cu")
		(net "M_B_CPU1_SA_CB<1>")
	)
	(segment
		(start 55.328058 -277.93696)
		(end 55.018432 -277.627334)
		(width 0.18288)
		(layer "In2.Cu")
		(net "M_B_CPU1_SA_CB<1>")
	)
	(segment
		(start 51.505358 -277.513796)
		(end 51.377342 -277.641812)
		(width 0.18288)
		(layer "In2.Cu")
		(net "M_B_CPU1_SA_CB<1>")
	)
	(segment
		(start 48.925988 -277.671276)
		(end 48.66767 -277.929594)
		(width 0.18288)
		(layer "In2.Cu")
		(net "M_B_CPU1_SA_CB<1>")
	)
	(segment
		(start 85.248496 -261.734554)
		(end 85.248496 -261.7343)
		(width 0.088646)
		(layer "In2.Cu")
		(net "M_B_CPU1_SA_CB<1>")
	)
	(segment
		(start 48.66767 -278.357076)
		(end 48.50765 -278.517096)
		(width 0.18288)
		(layer "In2.Cu")
		(net "M_B_CPU1_SA_CB<1>")
	)
	(segment
		(start 67.451732 -274.77466)
		(end 66.179192 -274.77466)
		(width 0.18288)
		(layer "In2.Cu")
		(net "M_B_CPU1_SA_CB<1>")
	)
	(segment
		(start 59.470544 -277.614126)
		(end 59.125358 -277.959312)
		(width 0.18288)
		(layer "In2.Cu")
		(net "M_B_CPU1_SA_CB<1>")
	)
	(segment
		(start 81.234788 -263.710166)
		(end 79.828898 -263.710166)
		(width 0.18288)
		(layer "In2.Cu")
		(net "M_B_CPU1_SA_CB<1>")
	)
	(segment
		(start 58.378598 -277.638002)
		(end 56.465978 -277.638002)
		(width 0.18288)
		(layer "In2.Cu")
		(net "M_B_CPU1_SA_CB<1>")
	)
	(segment
		(start 65.331594 -275.622258)
		(end 64.560704 -275.622258)
		(width 0.18288)
		(layer "In2.Cu")
		(net "M_B_CPU1_SA_CB<1>")
	)
	(segment
		(start 63.941198 -276.612604)
		(end 62.939676 -277.614126)
		(width 0.18288)
		(layer "In2.Cu")
		(net "M_B_CPU1_SA_CB<1>")
	)
	(segment
		(start 48.006 -278.517096)
		(end 47.83582 -278.346916)
		(width 0.18288)
		(layer "In2.Cu")
		(net "M_B_CPU1_SA_CB<1>")
	)
	(segment
		(start 58.699908 -277.959312)
		(end 58.378598 -277.638002)
		(width 0.18288)
		(layer "In2.Cu")
		(net "M_B_CPU1_SA_CB<1>")
	)
	(segment
		(start 82.1182 -263.345168)
		(end 81.753202 -263.710166)
		(width 0.088646)
		(layer "In2.Cu")
		(net "M_B_CPU1_SA_CB<1>")
	)
	(segment
		(start 54.137052 -277.753572)
		(end 52.700682 -277.753572)
		(width 0.18288)
		(layer "In2.Cu")
		(net "M_B_CPU1_SA_CB<1>")
	)
	(segment
		(start 78.287118 -265.251946)
		(end 76.046076 -266.180316)
		(width 0.18288)
		(layer "In2.Cu")
		(net "M_B_CPU1_SA_CB<1>")
	)
	(segment
		(start 49.546256 -277.217124)
		(end 49.546256 -277.495254)
		(width 0.18288)
		(layer "In2.Cu")
		(net "M_B_CPU1_SA_CB<1>")
	)
	(segment
		(start 48.66767 -277.929594)
		(end 48.66767 -278.357076)
		(width 0.18288)
		(layer "In2.Cu")
		(net "M_B_CPU1_SA_CB<1>")
	)
	(segment
		(start 51.377342 -277.641812)
		(end 50.579782 -277.641812)
		(width 0.18288)
		(layer "In2.Cu")
		(net "M_B_CPU1_SA_CB<1>")
	)
	(segment
		(start 54.26329 -277.627334)
		(end 54.137052 -277.753572)
		(width 0.18288)
		(layer "In2.Cu")
		(net "M_B_CPU1_SA_CB<1>")
	)
	(segment
		(start 49.73574 -277.02764)
		(end 49.546256 -277.217124)
		(width 0.18288)
		(layer "In2.Cu")
		(net "M_B_CPU1_SA_CB<1>")
	)
	(segment
		(start 52.460906 -277.513796)
		(end 51.505358 -277.513796)
		(width 0.18288)
		(layer "In2.Cu")
		(net "M_B_CPU1_SA_CB<1>")
	)
	(segment
		(start 47.83582 -277.409656)
		(end 47.64278 -277.216616)
		(width 0.18288)
		(layer "In2.Cu")
		(net "M_B_CPU1_SA_CB<1>")
	)
	(segment
		(start 83.727798 -261.809992)
		(end 82.192622 -263.345168)
		(width 0.088646)
		(layer "In2.Cu")
		(net "M_B_CPU1_SA_CB<1>")
	)
	(segment
		(start 82.192622 -263.345168)
		(end 82.1182 -263.345168)
		(width 0.088646)
		(layer "In2.Cu")
		(net "M_B_CPU1_SA_CB<1>")
	)
	(segment
		(start 79.828898 -263.710166)
		(end 78.287118 -265.251946)
		(width 0.18288)
		(layer "In2.Cu")
		(net "M_B_CPU1_SA_CB<1>")
	)
	(segment
		(start 50.227992 -277.02764)
		(end 49.73574 -277.02764)
		(width 0.18288)
		(layer "In2.Cu")
		(net "M_B_CPU1_SA_CB<1>")
	)
	(segment
		(start 47.83582 -278.346916)
		(end 47.83582 -277.409656)
		(width 0.18288)
		(layer "In2.Cu")
		(net "M_B_CPU1_SA_CB<1>")
	)
	(segment
		(start 50.388012 -277.18766)
		(end 50.227992 -277.02764)
		(width 0.18288)
		(layer "In2.Cu")
		(net "M_B_CPU1_SA_CB<1>")
	)
	(segment
		(start 63.941198 -276.241764)
		(end 63.941198 -276.612604)
		(width 0.18288)
		(layer "In2.Cu")
		(net "M_B_CPU1_SA_CB<1>")
	)
	(arc
		(start 86.188296 -261.734554)
		(mid 85.905594 -261.81033)
		(end 85.622892 -261.734554)
		(width 0.088646)
		(layer "In2.Cu")
		(net "M_B_CPU1_SA_CB<1>")
	)
	(arc
		(start 87.502492 -261.734554)
		(mid 87.315294 -261.684377)
		(end 87.128096 -261.734554)
		(width 0.088646)
		(layer "In2.Cu")
		(net "M_B_CPU1_SA_CB<1>")
	)
	(arc
		(start 87.128096 -261.734554)
		(mid 86.845394 -261.81033)
		(end 86.562692 -261.734554)
		(width 0.088646)
		(layer "In2.Cu")
		(net "M_B_CPU1_SA_CB<1>")
	)
	(arc
		(start 88.229694 -261.594092)
		(mid 87.892316 -261.799986)
		(end 87.502492 -261.734554)
		(width 0.088646)
		(layer "In2.Cu")
		(net "M_B_CPU1_SA_CB<1>")
	)
	(arc
		(start 85.622892 -261.734554)
		(mid 85.435694 -261.684377)
		(end 85.248496 -261.734554)
		(width 0.088646)
		(layer "In2.Cu")
		(net "M_B_CPU1_SA_CB<1>")
	)
	(arc
		(start 84.308696 -261.7343)
		(mid 84.17233 -261.790778)
		(end 84.025994 -261.809992)
		(width 0.088646)
		(layer "In2.Cu")
		(net "M_B_CPU1_SA_CB<1>")
	)
	(arc
		(start 84.683092 -261.7343)
		(mid 84.495894 -261.684157)
		(end 84.308696 -261.7343)
		(width 0.088646)
		(layer "In2.Cu")
		(net "M_B_CPU1_SA_CB<1>")
	)
	(arc
		(start 85.248496 -261.7343)
		(mid 84.965794 -261.810076)
		(end 84.683092 -261.7343)
		(width 0.088646)
		(layer "In2.Cu")
		(net "M_B_CPU1_SA_CB<1>")
	)
	(arc
		(start 86.562692 -261.734554)
		(mid 86.375494 -261.684377)
		(end 86.188296 -261.734554)
		(width 0.088646)
		(layer "In2.Cu")
		(net "M_B_CPU1_SA_CB<1>")
	)
	(segment
		(start 45.859446 -278.916638)
		(end 44.490386 -278.916638)
		(width 0.20066)
		(layer "F.Cu")
		(net "M_B_CPU1_SA_CB<0>")
	)
	(segment
		(start 40.520112 -278.982678)
		(end 40.347392 -279.155398)
		(width 0.20066)
		(layer "F.Cu")
		(net "M_B_CPU1_SA_CB<0>")
	)
	(segment
		(start 46.964346 -278.916638)
		(end 45.859446 -278.916638)
		(width 0.20066)
		(layer "F.Cu")
		(net "M_B_CPU1_SA_CB<0>")
	)
	(segment
		(start 41.547542 -278.491696)
		(end 41.299638 -278.491696)
		(width 0.101854)
		(layer "F.Cu")
		(net "M_B_CPU1_SA_CB<0>")
	)
	(segment
		(start 40.520112 -278.693118)
		(end 40.520112 -278.982678)
		(width 0.20066)
		(layer "F.Cu")
		(net "M_B_CPU1_SA_CB<0>")
	)
	(segment
		(start 43.616626 -278.491696)
		(end 41.547542 -278.491696)
		(width 0.1016)
		(layer "F.Cu")
		(net "M_B_CPU1_SA_CB<0>")
	)
	(segment
		(start 41.299638 -278.491696)
		(end 41.29151 -278.483568)
		(width 0.101854)
		(layer "F.Cu")
		(net "M_B_CPU1_SA_CB<0>")
	)
	(segment
		(start 40.729662 -278.483568)
		(end 40.520112 -278.693118)
		(width 0.20066)
		(layer "F.Cu")
		(net "M_B_CPU1_SA_CB<0>")
	)
	(segment
		(start 39.888668 -279.155398)
		(end 39.649908 -278.916638)
		(width 0.20066)
		(layer "F.Cu")
		(net "M_B_CPU1_SA_CB<0>")
	)
	(segment
		(start 44.065444 -278.491696)
		(end 43.616626 -278.491696)
		(width 0.20066)
		(layer "F.Cu")
		(net "M_B_CPU1_SA_CB<0>")
	)
	(segment
		(start 89.194894 -261.522718)
		(end 89.195148 -261.522972)
		(width 0.20066)
		(layer "F.Cu")
		(net "M_B_CPU1_SA_CB<0>")
	)
	(segment
		(start 40.347392 -279.155398)
		(end 39.888668 -279.155398)
		(width 0.20066)
		(layer "F.Cu")
		(net "M_B_CPU1_SA_CB<0>")
	)
	(segment
		(start 41.29151 -278.483568)
		(end 40.729662 -278.483568)
		(width 0.20066)
		(layer "F.Cu")
		(net "M_B_CPU1_SA_CB<0>")
	)
	(segment
		(start 89.195148 -261.522972)
		(end 89.195148 -262.058658)
		(width 0.20066)
		(layer "F.Cu")
		(net "M_B_CPU1_SA_CB<0>")
	)
	(segment
		(start 44.490386 -278.916638)
		(end 44.065444 -278.491696)
		(width 0.20066)
		(layer "F.Cu")
		(net "M_B_CPU1_SA_CB<0>")
	)
	(segment
		(start 39.649908 -278.916638)
		(end 38.315646 -278.916638)
		(width 0.20066)
		(layer "F.Cu")
		(net "M_B_CPU1_SA_CB<0>")
	)
	(segment
		(start 59.177682 -279.532588)
		(end 58.52795 -279.532588)
		(width 0.18288)
		(layer "In2.Cu")
		(net "M_B_CPU1_SA_CB<0>")
	)
	(segment
		(start 50.137822 -279.341834)
		(end 50.093626 -279.38603)
		(width 0.18288)
		(layer "In2.Cu")
		(net "M_B_CPU1_SA_CB<0>")
	)
	(segment
		(start 47.433738 -279.38603)
		(end 46.964346 -278.916638)
		(width 0.18288)
		(layer "In2.Cu")
		(net "M_B_CPU1_SA_CB<0>")
	)
	(segment
		(start 81.862676 -264.401046)
		(end 81.234788 -264.401046)
		(width 0.088646)
		(layer "In2.Cu")
		(net "M_B_CPU1_SA_CB<0>")
	)
	(segment
		(start 66.610992 -277.740364)
		(end 65.868804 -278.482552)
		(width 0.18288)
		(layer "In2.Cu")
		(net "M_B_CPU1_SA_CB<0>")
	)
	(segment
		(start 56.562498 -279.36317)
		(end 55.720488 -280.20518)
		(width 0.18288)
		(layer "In2.Cu")
		(net "M_B_CPU1_SA_CB<0>")
	)
	(segment
		(start 89.507822 -262.058658)
		(end 89.564972 -262.001508)
		(width 0.088646)
		(layer "In2.Cu")
		(net "M_B_CPU1_SA_CB<0>")
	)
	(segment
		(start 89.195148 -262.058658)
		(end 89.507822 -262.058658)
		(width 0.088646)
		(layer "In2.Cu")
		(net "M_B_CPU1_SA_CB<0>")
	)
	(segment
		(start 65.868804 -278.482552)
		(end 63.80353 -278.482552)
		(width 0.18288)
		(layer "In2.Cu")
		(net "M_B_CPU1_SA_CB<0>")
	)
	(segment
		(start 58.358532 -279.36317)
		(end 56.562498 -279.36317)
		(width 0.18288)
		(layer "In2.Cu")
		(net "M_B_CPU1_SA_CB<0>")
	)
	(segment
		(start 63.80353 -278.482552)
		(end 63.623698 -278.510492)
		(width 0.18288)
		(layer "In2.Cu")
		(net "M_B_CPU1_SA_CB<0>")
	)
	(segment
		(start 55.720488 -280.20518)
		(end 51.97221 -280.20518)
		(width 0.18288)
		(layer "In2.Cu")
		(net "M_B_CPU1_SA_CB<0>")
	)
	(segment
		(start 50.093626 -279.38603)
		(end 47.433738 -279.38603)
		(width 0.18288)
		(layer "In2.Cu")
		(net "M_B_CPU1_SA_CB<0>")
	)
	(segment
		(start 51.556158 -279.789128)
		(end 51.556158 -279.534874)
		(width 0.18288)
		(layer "In2.Cu")
		(net "M_B_CPU1_SA_CB<0>")
	)
	(segment
		(start 76.621894 -267.041884)
		(end 66.610992 -277.052786)
		(width 0.18288)
		(layer "In2.Cu")
		(net "M_B_CPU1_SA_CB<0>")
	)
	(segment
		(start 51.556158 -279.534874)
		(end 51.363118 -279.341834)
		(width 0.18288)
		(layer "In2.Cu")
		(net "M_B_CPU1_SA_CB<0>")
	)
	(segment
		(start 88.549988 -262.541004)
		(end 88.537796 -262.548116)
		(width 0.088646)
		(layer "In2.Cu")
		(net "M_B_CPU1_SA_CB<0>")
	)
	(segment
		(start 80.59293 -264.401046)
		(end 78.892908 -266.101068)
		(width 0.18288)
		(layer "In2.Cu")
		(net "M_B_CPU1_SA_CB<0>")
	)
	(segment
		(start 63.623698 -278.510492)
		(end 61.644784 -279.33015)
		(width 0.18288)
		(layer "In2.Cu")
		(net "M_B_CPU1_SA_CB<0>")
	)
	(segment
		(start 61.644784 -279.33015)
		(end 59.38012 -279.33015)
		(width 0.18288)
		(layer "In2.Cu")
		(net "M_B_CPU1_SA_CB<0>")
	)
	(segment
		(start 83.766152 -262.49757)
		(end 81.862676 -264.401046)
		(width 0.088646)
		(layer "In2.Cu")
		(net "M_B_CPU1_SA_CB<0>")
	)
	(segment
		(start 66.610992 -277.052786)
		(end 66.610992 -277.740364)
		(width 0.18288)
		(layer "In2.Cu")
		(net "M_B_CPU1_SA_CB<0>")
	)
	(segment
		(start 84.025994 -262.49757)
		(end 83.766152 -262.49757)
		(width 0.088646)
		(layer "In2.Cu")
		(net "M_B_CPU1_SA_CB<0>")
	)
	(segment
		(start 59.38012 -279.33015)
		(end 59.177682 -279.532588)
		(width 0.18288)
		(layer "In2.Cu")
		(net "M_B_CPU1_SA_CB<0>")
	)
	(segment
		(start 58.52795 -279.532588)
		(end 58.358532 -279.36317)
		(width 0.18288)
		(layer "In2.Cu")
		(net "M_B_CPU1_SA_CB<0>")
	)
	(segment
		(start 78.892908 -266.101068)
		(end 76.621894 -267.041884)
		(width 0.18288)
		(layer "In2.Cu")
		(net "M_B_CPU1_SA_CB<0>")
	)
	(segment
		(start 51.97221 -280.20518)
		(end 51.556158 -279.789128)
		(width 0.18288)
		(layer "In2.Cu")
		(net "M_B_CPU1_SA_CB<0>")
	)
	(segment
		(start 81.234788 -264.401046)
		(end 80.59293 -264.401046)
		(width 0.18288)
		(layer "In2.Cu")
		(net "M_B_CPU1_SA_CB<0>")
	)
	(segment
		(start 89.00795 -261.7343)
		(end 88.99906 -261.73938)
		(width 0.088646)
		(layer "In2.Cu")
		(net "M_B_CPU1_SA_CB<0>")
	)
	(segment
		(start 51.363118 -279.341834)
		(end 50.137822 -279.341834)
		(width 0.18288)
		(layer "In2.Cu")
		(net "M_B_CPU1_SA_CB<0>")
	)
	(arc
		(start 87.972392 -262.548116)
		(mid 87.785194 -262.497973)
		(end 87.597996 -262.548116)
		(width 0.088646)
		(layer "In2.Cu")
		(net "M_B_CPU1_SA_CB<0>")
	)
	(arc
		(start 89.382346 -261.7343)
		(mid 89.195148 -261.684157)
		(end 89.00795 -261.7343)
		(width 0.088646)
		(layer "In2.Cu")
		(net "M_B_CPU1_SA_CB<0>")
	)
	(arc
		(start 88.99906 -261.73938)
		(mid 88.868146 -261.87574)
		(end 88.820498 -262.058658)
		(width 0.088646)
		(layer "In2.Cu")
		(net "M_B_CPU1_SA_CB<0>")
	)
	(arc
		(start 84.778596 -262.548116)
		(mid 84.495894 -262.623892)
		(end 84.213192 -262.548116)
		(width 0.088646)
		(layer "In2.Cu")
		(net "M_B_CPU1_SA_CB<0>")
	)
	(arc
		(start 88.537796 -262.548116)
		(mid 88.255094 -262.623892)
		(end 87.972392 -262.548116)
		(width 0.088646)
		(layer "In2.Cu")
		(net "M_B_CPU1_SA_CB<0>")
	)
	(arc
		(start 89.564972 -262.001508)
		(mid 89.504029 -261.847145)
		(end 89.382346 -261.7343)
		(width 0.088646)
		(layer "In2.Cu")
		(net "M_B_CPU1_SA_CB<0>")
	)
	(arc
		(start 85.152992 -262.548116)
		(mid 84.965794 -262.497973)
		(end 84.778596 -262.548116)
		(width 0.088646)
		(layer "In2.Cu")
		(net "M_B_CPU1_SA_CB<0>")
	)
	(arc
		(start 87.597996 -262.548116)
		(mid 87.315294 -262.623892)
		(end 87.032592 -262.548116)
		(width 0.088646)
		(layer "In2.Cu")
		(net "M_B_CPU1_SA_CB<0>")
	)
	(arc
		(start 86.092792 -262.548116)
		(mid 85.905594 -262.497973)
		(end 85.718396 -262.548116)
		(width 0.088646)
		(layer "In2.Cu")
		(net "M_B_CPU1_SA_CB<0>")
	)
	(arc
		(start 86.658196 -262.548116)
		(mid 86.375494 -262.623892)
		(end 86.092792 -262.548116)
		(width 0.088646)
		(layer "In2.Cu")
		(net "M_B_CPU1_SA_CB<0>")
	)
	(arc
		(start 84.213192 -262.548116)
		(mid 84.122916 -262.510542)
		(end 84.025994 -262.49757)
		(width 0.088646)
		(layer "In2.Cu")
		(net "M_B_CPU1_SA_CB<0>")
	)
	(arc
		(start 87.032592 -262.548116)
		(mid 86.845394 -262.497973)
		(end 86.658196 -262.548116)
		(width 0.088646)
		(layer "In2.Cu")
		(net "M_B_CPU1_SA_CB<0>")
	)
	(arc
		(start 85.718396 -262.548116)
		(mid 85.435694 -262.623892)
		(end 85.152992 -262.548116)
		(width 0.088646)
		(layer "In2.Cu")
		(net "M_B_CPU1_SA_CB<0>")
	)
	(arc
		(start 88.820498 -262.058658)
		(mid 88.748263 -262.335182)
		(end 88.549988 -262.541004)
		(width 0.088646)
		(layer "In2.Cu")
		(net "M_B_CPU1_SA_CB<0>")
	)
	(segment
		(start 93.783912 -249.342148)
		(end 93.784166 -249.341894)
		(width 0.20066)
		(layer "F.Cu")
		(net "M_B_CPU1_SA_CA<6>")
	)
	(segment
		(start 43.616626 -260.641846)
		(end 43.285918 -260.641846)
		(width 0.101854)
		(layer "F.Cu")
		(net "M_B_CPU1_SA_CA<6>")
	)
	(segment
		(start 40.36568 -261.278116)
		(end 39.861236 -261.278116)
		(width 0.20066)
		(layer "F.Cu")
		(net "M_B_CPU1_SA_CA<6>")
	)
	(segment
		(start 43.285918 -260.641846)
		(end 41.3004 -260.641846)
		(width 0.1016)
		(layer "F.Cu")
		(net "M_B_CPU1_SA_CA<6>")
	)
	(segment
		(start 40.682672 -260.632956)
		(end 40.520112 -260.795516)
		(width 0.20066)
		(layer "F.Cu")
		(net "M_B_CPU1_SA_CA<6>")
	)
	(segment
		(start 41.3004 -260.641846)
		(end 41.29151 -260.632956)
		(width 0.1016)
		(layer "F.Cu")
		(net "M_B_CPU1_SA_CA<6>")
	)
	(segment
		(start 40.520112 -261.123684)
		(end 40.36568 -261.278116)
		(width 0.20066)
		(layer "F.Cu")
		(net "M_B_CPU1_SA_CA<6>")
	)
	(segment
		(start 44.22013 -261.066788)
		(end 43.795188 -260.641846)
		(width 0.20066)
		(layer "F.Cu")
		(net "M_B_CPU1_SA_CA<6>")
	)
	(segment
		(start 39.649908 -261.066788)
		(end 38.315646 -261.066788)
		(width 0.20066)
		(layer "F.Cu")
		(net "M_B_CPU1_SA_CA<6>")
	)
	(segment
		(start 45.859446 -261.066788)
		(end 44.22013 -261.066788)
		(width 0.20066)
		(layer "F.Cu")
		(net "M_B_CPU1_SA_CA<6>")
	)
	(segment
		(start 46.964346 -261.066788)
		(end 45.859446 -261.066788)
		(width 0.20066)
		(layer "F.Cu")
		(net "M_B_CPU1_SA_CA<6>")
	)
	(segment
		(start 43.795188 -260.641846)
		(end 43.616626 -260.641846)
		(width 0.20066)
		(layer "F.Cu")
		(net "M_B_CPU1_SA_CA<6>")
	)
	(segment
		(start 40.520112 -260.795516)
		(end 40.520112 -261.123684)
		(width 0.20066)
		(layer "F.Cu")
		(net "M_B_CPU1_SA_CA<6>")
	)
	(segment
		(start 41.29151 -260.632956)
		(end 40.682672 -260.632956)
		(width 0.20066)
		(layer "F.Cu")
		(net "M_B_CPU1_SA_CA<6>")
	)
	(segment
		(start 39.861236 -261.278116)
		(end 39.649908 -261.066788)
		(width 0.20066)
		(layer "F.Cu")
		(net "M_B_CPU1_SA_CA<6>")
	)
	(segment
		(start 93.784166 -249.341894)
		(end 93.784166 -248.806208)
		(width 0.20066)
		(layer "F.Cu")
		(net "M_B_CPU1_SA_CA<6>")
	)
	(segment
		(start 94.818962 -249.797062)
		(end 95.006922 -249.985022)
		(width 0.088646)
		(layer "In2.Cu")
		(net "M_B_CPU1_SA_CA<6>")
	)
	(segment
		(start 51.245516 -261.49173)
		(end 49.07788 -261.49173)
		(width 0.18288)
		(layer "In2.Cu")
		(net "M_B_CPU1_SA_CA<6>")
	)
	(segment
		(start 58.257948 -257.784854)
		(end 56.691276 -258.901946)
		(width 0.18288)
		(layer "In2.Cu")
		(net "M_B_CPU1_SA_CA<6>")
	)
	(segment
		(start 79.641446 -255.897126)
		(end 72.327516 -255.897126)
		(width 0.18288)
		(layer "In2.Cu")
		(net "M_B_CPU1_SA_CA<6>")
	)
	(segment
		(start 49.07788 -261.49173)
		(end 48.936656 -261.632954)
		(width 0.18288)
		(layer "In2.Cu")
		(net "M_B_CPU1_SA_CA<6>")
	)
	(segment
		(start 51.515264 -261.221982)
		(end 51.245516 -261.49173)
		(width 0.18288)
		(layer "In2.Cu")
		(net "M_B_CPU1_SA_CA<6>")
	)
	(segment
		(start 56.55056 -258.957572)
		(end 55.711852 -258.957572)
		(width 0.18288)
		(layer "In2.Cu")
		(net "M_B_CPU1_SA_CA<6>")
	)
	(segment
		(start 94.818962 -249.61977)
		(end 94.818962 -249.797062)
		(width 0.088646)
		(layer "In2.Cu")
		(net "M_B_CPU1_SA_CA<6>")
	)
	(segment
		(start 91.962732 -252.628908)
		(end 82.909664 -252.628908)
		(width 0.18288)
		(layer "In2.Cu")
		(net "M_B_CPU1_SA_CA<6>")
	)
	(segment
		(start 55.333392 -259.06095)
		(end 52.596288 -260.676898)
		(width 0.18288)
		(layer "In2.Cu")
		(net "M_B_CPU1_SA_CA<6>")
	)
	(segment
		(start 52.430426 -260.84276)
		(end 51.515264 -261.221982)
		(width 0.18288)
		(layer "In2.Cu")
		(net "M_B_CPU1_SA_CA<6>")
	)
	(segment
		(start 48.936656 -261.632954)
		(end 48.331628 -261.632954)
		(width 0.18288)
		(layer "In2.Cu")
		(net "M_B_CPU1_SA_CA<6>")
	)
	(segment
		(start 95.006922 -250.114562)
		(end 95.006922 -250.877832)
		(width 0.18288)
		(layer "In2.Cu")
		(net "M_B_CPU1_SA_CA<6>")
	)
	(segment
		(start 95.006922 -250.877832)
		(end 94.169992 -251.714762)
		(width 0.18288)
		(layer "In2.Cu")
		(net "M_B_CPU1_SA_CA<6>")
	)
	(segment
		(start 94.508574 -249.11431)
		(end 94.536514 -249.130566)
		(width 0.088646)
		(layer "In2.Cu")
		(net "M_B_CPU1_SA_CA<6>")
	)
	(segment
		(start 48.331628 -261.632954)
		(end 46.964346 -261.066788)
		(width 0.18288)
		(layer "In2.Cu")
		(net "M_B_CPU1_SA_CA<6>")
	)
	(segment
		(start 59.631834 -257.559302)
		(end 58.257948 -257.784854)
		(width 0.18288)
		(layer "In2.Cu")
		(net "M_B_CPU1_SA_CA<6>")
	)
	(segment
		(start 82.909664 -252.628908)
		(end 79.641446 -255.897126)
		(width 0.18288)
		(layer "In2.Cu")
		(net "M_B_CPU1_SA_CA<6>")
	)
	(segment
		(start 72.327516 -255.897126)
		(end 71.867522 -256.087626)
		(width 0.18288)
		(layer "In2.Cu")
		(net "M_B_CPU1_SA_CA<6>")
	)
	(segment
		(start 94.169992 -251.714762)
		(end 91.962732 -252.628908)
		(width 0.18288)
		(layer "In2.Cu")
		(net "M_B_CPU1_SA_CA<6>")
	)
	(segment
		(start 71.867522 -256.087626)
		(end 70.985888 -256.452624)
		(width 0.18288)
		(layer "In2.Cu")
		(net "M_B_CPU1_SA_CA<6>")
	)
	(segment
		(start 56.691276 -258.901946)
		(end 56.55056 -258.957572)
		(width 0.18288)
		(layer "In2.Cu")
		(net "M_B_CPU1_SA_CA<6>")
	)
	(segment
		(start 65.42151 -257.559302)
		(end 59.631834 -257.559302)
		(width 0.18288)
		(layer "In2.Cu")
		(net "M_B_CPU1_SA_CA<6>")
	)
	(segment
		(start 95.006922 -249.985022)
		(end 95.006922 -250.114562)
		(width 0.088646)
		(layer "In2.Cu")
		(net "M_B_CPU1_SA_CA<6>")
	)
	(segment
		(start 52.596288 -260.676898)
		(end 52.430426 -260.84276)
		(width 0.18288)
		(layer "In2.Cu")
		(net "M_B_CPU1_SA_CA<6>")
	)
	(segment
		(start 70.985888 -256.452624)
		(end 65.42151 -257.559302)
		(width 0.18288)
		(layer "In2.Cu")
		(net "M_B_CPU1_SA_CA<6>")
	)
	(segment
		(start 55.711852 -258.957572)
		(end 55.333392 -259.06095)
		(width 0.18288)
		(layer "In2.Cu")
		(net "M_B_CPU1_SA_CA<6>")
	)
	(segment
		(start 93.784166 -248.806208)
		(end 94.508574 -249.11431)
		(width 0.088646)
		(layer "In2.Cu")
		(net "M_B_CPU1_SA_CA<6>")
	)
	(arc
		(start 94.536514 -249.130566)
		(mid 94.743274 -249.337329)
		(end 94.818962 -249.61977)
		(width 0.088646)
		(layer "In2.Cu")
		(net "M_B_CPU1_SA_CA<6>")
	)
	(segment
		(start 47.882302 -261.912354)
		(end 47.753778 -262.040878)
		(width 0.20066)
		(layer "F.Cu")
		(net "M_B_CPU1_SA_CA<5>")
	)
	(segment
		(start 47.753778 -262.040878)
		(end 47.753778 -262.192516)
		(width 0.20066)
		(layer "F.Cu")
		(net "M_B_CPU1_SA_CA<5>")
	)
	(segment
		(start 90.134694 -253.383796)
		(end 90.134694 -253.919736)
		(width 0.20066)
		(layer "F.Cu")
		(net "M_B_CPU1_SA_CA<5>")
	)
	(segment
		(start 44.38142 -262.355838)
		(end 44.238926 -262.213344)
		(width 0.20066)
		(layer "F.Cu")
		(net "M_B_CPU1_SA_CA<5>")
	)
	(segment
		(start 48.935894 -262.12419)
		(end 48.489362 -262.12419)
		(width 0.20066)
		(layer "F.Cu")
		(net "M_B_CPU1_SA_CA<5>")
	)
	(segment
		(start 48.489362 -262.12419)
		(end 48.277526 -261.912354)
		(width 0.20066)
		(layer "F.Cu")
		(net "M_B_CPU1_SA_CA<5>")
	)
	(segment
		(start 48.277526 -261.912354)
		(end 47.882302 -261.912354)
		(width 0.20066)
		(layer "F.Cu")
		(net "M_B_CPU1_SA_CA<5>")
	)
	(segment
		(start 47.753778 -262.192516)
		(end 47.60468 -262.341614)
		(width 0.20066)
		(layer "F.Cu")
		(net "M_B_CPU1_SA_CA<5>")
	)
	(segment
		(start 44.112942 -261.916672)
		(end 42.415714 -261.916672)
		(width 0.20066)
		(layer "F.Cu")
		(net "M_B_CPU1_SA_CA<5>")
	)
	(segment
		(start 49.959514 -261.916672)
		(end 49.143412 -261.916672)
		(width 0.20066)
		(layer "F.Cu")
		(net "M_B_CPU1_SA_CA<5>")
	)
	(segment
		(start 47.060358 -262.341614)
		(end 44.987464 -262.341614)
		(width 0.1016)
		(layer "F.Cu")
		(net "M_B_CPU1_SA_CA<5>")
	)
	(segment
		(start 44.735242 -262.355838)
		(end 44.38142 -262.355838)
		(width 0.20066)
		(layer "F.Cu")
		(net "M_B_CPU1_SA_CA<5>")
	)
	(segment
		(start 47.60468 -262.341614)
		(end 47.060358 -262.341614)
		(width 0.20066)
		(layer "F.Cu")
		(net "M_B_CPU1_SA_CA<5>")
	)
	(segment
		(start 44.987464 -262.341614)
		(end 44.749466 -262.341614)
		(width 0.101854)
		(layer "F.Cu")
		(net "M_B_CPU1_SA_CA<5>")
	)
	(segment
		(start 44.238926 -262.042656)
		(end 44.112942 -261.916672)
		(width 0.20066)
		(layer "F.Cu")
		(net "M_B_CPU1_SA_CA<5>")
	)
	(segment
		(start 49.143412 -261.916672)
		(end 48.935894 -262.12419)
		(width 0.20066)
		(layer "F.Cu")
		(net "M_B_CPU1_SA_CA<5>")
	)
	(segment
		(start 51.089814 -261.916672)
		(end 49.959514 -261.916672)
		(width 0.20066)
		(layer "F.Cu")
		(net "M_B_CPU1_SA_CA<5>")
	)
	(segment
		(start 44.749466 -262.341614)
		(end 44.735242 -262.355838)
		(width 0.101854)
		(layer "F.Cu")
		(net "M_B_CPU1_SA_CA<5>")
	)
	(segment
		(start 44.238926 -262.213344)
		(end 44.238926 -262.042656)
		(width 0.20066)
		(layer "F.Cu")
		(net "M_B_CPU1_SA_CA<5>")
	)
	(segment
		(start 63.413132 -258.56184)
		(end 63.253112 -258.72186)
		(width 0.18288)
		(layer "In2.Cu")
		(net "M_B_CPU1_SA_CA<5>")
	)
	(segment
		(start 82.521806 -253.505462)
		(end 79.784702 -256.242566)
		(width 0.18288)
		(layer "In2.Cu")
		(net "M_B_CPU1_SA_CA<5>")
	)
	(segment
		(start 60.274454 -258.089908)
		(end 59.563254 -258.089908)
		(width 0.18288)
		(layer "In2.Cu")
		(net "M_B_CPU1_SA_CA<5>")
	)
	(segment
		(start 62.803532 -258.72186)
		(end 62.63386 -258.552188)
		(width 0.18288)
		(layer "In2.Cu")
		(net "M_B_CPU1_SA_CA<5>")
	)
	(segment
		(start 88.457024 -253.604014)
		(end 88.442292 -253.595378)
		(width 0.088646)
		(layer "In2.Cu")
		(net "M_B_CPU1_SA_CA<5>")
	)
	(segment
		(start 63.253112 -258.72186)
		(end 62.803532 -258.72186)
		(width 0.18288)
		(layer "In2.Cu")
		(net "M_B_CPU1_SA_CA<5>")
	)
	(segment
		(start 59.324494 -258.780026)
		(end 59.121548 -258.982972)
		(width 0.18288)
		(layer "In2.Cu")
		(net "M_B_CPU1_SA_CA<5>")
	)
	(segment
		(start 67.659504 -257.660394)
		(end 67.507612 -257.887216)
		(width 0.18288)
		(layer "In2.Cu")
		(net "M_B_CPU1_SA_CA<5>")
	)
	(segment
		(start 67.412362 -258.397248)
		(end 67.100704 -258.459478)
		(width 0.18288)
		(layer "In2.Cu")
		(net "M_B_CPU1_SA_CA<5>")
	)
	(segment
		(start 52.634642 -261.482332)
		(end 52.22748 -261.482332)
		(width 0.18288)
		(layer "In2.Cu")
		(net "M_B_CPU1_SA_CA<5>")
	)
	(segment
		(start 60.660534 -258.982972)
		(end 60.493656 -258.816094)
		(width 0.18288)
		(layer "In2.Cu")
		(net "M_B_CPU1_SA_CA<5>")
	)
	(segment
		(start 54.123082 -261.548372)
		(end 52.700682 -261.548372)
		(width 0.18288)
		(layer "In2.Cu")
		(net "M_B_CPU1_SA_CA<5>")
	)
	(segment
		(start 63.413132 -258.235196)
		(end 63.413132 -258.56184)
		(width 0.18288)
		(layer "In2.Cu")
		(net "M_B_CPU1_SA_CA<5>")
	)
	(segment
		(start 63.573152 -258.075176)
		(end 63.413132 -258.235196)
		(width 0.18288)
		(layer "In2.Cu")
		(net "M_B_CPU1_SA_CA<5>")
	)
	(segment
		(start 84.565998 -253.505462)
		(end 83.876134 -253.505462)
		(width 0.088646)
		(layer "In2.Cu")
		(net "M_B_CPU1_SA_CA<5>")
	)
	(segment
		(start 66.590926 -257.872992)
		(end 65.6082 -258.068572)
		(width 0.18288)
		(layer "In2.Cu")
		(net "M_B_CPU1_SA_CA<5>")
	)
	(segment
		(start 58.593482 -259.450332)
		(end 58.230262 -259.813552)
		(width 0.18288)
		(layer "In2.Cu")
		(net "M_B_CPU1_SA_CA<5>")
	)
	(segment
		(start 59.121548 -258.982972)
		(end 58.767218 -258.982972)
		(width 0.18288)
		(layer "In2.Cu")
		(net "M_B_CPU1_SA_CA<5>")
	)
	(segment
		(start 54.338982 -260.760972)
		(end 54.338982 -261.332472)
		(width 0.18288)
		(layer "In2.Cu")
		(net "M_B_CPU1_SA_CA<5>")
	)
	(segment
		(start 66.873882 -258.30784)
		(end 66.817494 -258.02463)
		(width 0.18288)
		(layer "In2.Cu")
		(net "M_B_CPU1_SA_CA<5>")
	)
	(segment
		(start 72.827134 -256.242566)
		(end 72.258174 -256.478278)
		(width 0.18288)
		(layer "In2.Cu")
		(net "M_B_CPU1_SA_CA<5>")
	)
	(segment
		(start 62.63386 -258.228592)
		(end 62.47384 -258.068572)
		(width 0.18288)
		(layer "In2.Cu")
		(net "M_B_CPU1_SA_CA<5>")
	)
	(segment
		(start 52.700682 -261.548372)
		(end 52.634642 -261.482332)
		(width 0.18288)
		(layer "In2.Cu")
		(net "M_B_CPU1_SA_CA<5>")
	)
	(segment
		(start 62.63386 -258.552188)
		(end 62.63386 -258.228592)
		(width 0.18288)
		(layer "In2.Cu")
		(net "M_B_CPU1_SA_CA<5>")
	)
	(segment
		(start 72.258174 -256.478278)
		(end 71.015352 -256.992882)
		(width 0.18288)
		(layer "In2.Cu")
		(net "M_B_CPU1_SA_CA<5>")
	)
	(segment
		(start 83.876134 -253.505462)
		(end 82.521806 -253.505462)
		(width 0.18288)
		(layer "In2.Cu")
		(net "M_B_CPU1_SA_CA<5>")
	)
	(segment
		(start 55.095648 -260.375146)
		(end 54.792372 -260.678422)
		(width 0.18288)
		(layer "In2.Cu")
		(net "M_B_CPU1_SA_CA<5>")
	)
	(segment
		(start 84.683346 -253.595378)
		(end 84.683092 -253.595378)
		(width 0.088646)
		(layer "In2.Cu")
		(net "M_B_CPU1_SA_CA<5>")
	)
	(segment
		(start 68.90639 -257.871214)
		(end 68.499736 -257.951732)
		(width 0.18288)
		(layer "In2.Cu")
		(net "M_B_CPU1_SA_CA<5>")
	)
	(segment
		(start 66.817494 -258.02463)
		(end 66.590926 -257.872992)
		(width 0.18288)
		(layer "In2.Cu")
		(net "M_B_CPU1_SA_CA<5>")
	)
	(segment
		(start 54.792372 -260.678422)
		(end 54.421532 -260.678422)
		(width 0.18288)
		(layer "In2.Cu")
		(net "M_B_CPU1_SA_CA<5>")
	)
	(segment
		(start 67.564 -258.170426)
		(end 67.412362 -258.397248)
		(width 0.18288)
		(layer "In2.Cu")
		(net "M_B_CPU1_SA_CA<5>")
	)
	(segment
		(start 67.100704 -258.459478)
		(end 66.873882 -258.30784)
		(width 0.18288)
		(layer "In2.Cu")
		(net "M_B_CPU1_SA_CA<5>")
	)
	(segment
		(start 62.47384 -258.068572)
		(end 61.776356 -258.068572)
		(width 0.18288)
		(layer "In2.Cu")
		(net "M_B_CPU1_SA_CA<5>")
	)
	(segment
		(start 55.534814 -259.542788)
		(end 55.095648 -259.981954)
		(width 0.18288)
		(layer "In2.Cu")
		(net "M_B_CPU1_SA_CA<5>")
	)
	(segment
		(start 71.015352 -256.992882)
		(end 69.260466 -257.341624)
		(width 0.18288)
		(layer "In2.Cu")
		(net "M_B_CPU1_SA_CA<5>")
	)
	(segment
		(start 58.767218 -258.982972)
		(end 58.593482 -259.156708)
		(width 0.18288)
		(layer "In2.Cu")
		(net "M_B_CPU1_SA_CA<5>")
	)
	(segment
		(start 61.776356 -258.068572)
		(end 61.616336 -258.228592)
		(width 0.18288)
		(layer "In2.Cu")
		(net "M_B_CPU1_SA_CA<5>")
	)
	(segment
		(start 61.456316 -258.982972)
		(end 60.660534 -258.982972)
		(width 0.18288)
		(layer "In2.Cu")
		(net "M_B_CPU1_SA_CA<5>")
	)
	(segment
		(start 67.971162 -257.598164)
		(end 67.659504 -257.660394)
		(width 0.18288)
		(layer "In2.Cu")
		(net "M_B_CPU1_SA_CA<5>")
	)
	(segment
		(start 54.421532 -260.678422)
		(end 54.338982 -260.760972)
		(width 0.18288)
		(layer "In2.Cu")
		(net "M_B_CPU1_SA_CA<5>")
	)
	(segment
		(start 89.411302 -253.612396)
		(end 89.382092 -253.595378)
		(width 0.088646)
		(layer "In2.Cu")
		(net "M_B_CPU1_SA_CA<5>")
	)
	(segment
		(start 60.493656 -258.30911)
		(end 60.274454 -258.089908)
		(width 0.18288)
		(layer "In2.Cu")
		(net "M_B_CPU1_SA_CA<5>")
	)
	(segment
		(start 59.324494 -258.328668)
		(end 59.324494 -258.780026)
		(width 0.18288)
		(layer "In2.Cu")
		(net "M_B_CPU1_SA_CA<5>")
	)
	(segment
		(start 52.045616 -261.55777)
		(end 51.686968 -261.916418)
		(width 0.18288)
		(layer "In2.Cu")
		(net "M_B_CPU1_SA_CA<5>")
	)
	(segment
		(start 68.499736 -257.951732)
		(end 67.971162 -257.598164)
		(width 0.18288)
		(layer "In2.Cu")
		(net "M_B_CPU1_SA_CA<5>")
	)
	(segment
		(start 58.230262 -259.813552)
		(end 56.615584 -259.813552)
		(width 0.18288)
		(layer "In2.Cu")
		(net "M_B_CPU1_SA_CA<5>")
	)
	(segment
		(start 58.593482 -259.156708)
		(end 58.593482 -259.450332)
		(width 0.18288)
		(layer "In2.Cu")
		(net "M_B_CPU1_SA_CA<5>")
	)
	(segment
		(start 59.563254 -258.089908)
		(end 59.324494 -258.328668)
		(width 0.18288)
		(layer "In2.Cu")
		(net "M_B_CPU1_SA_CA<5>")
	)
	(segment
		(start 67.507612 -257.887216)
		(end 67.564 -258.170426)
		(width 0.18288)
		(layer "In2.Cu")
		(net "M_B_CPU1_SA_CA<5>")
	)
	(segment
		(start 90.134694 -253.919736)
		(end 89.411302 -253.612396)
		(width 0.088646)
		(layer "In2.Cu")
		(net "M_B_CPU1_SA_CA<5>")
	)
	(segment
		(start 64.425322 -258.075176)
		(end 63.573152 -258.075176)
		(width 0.18288)
		(layer "In2.Cu")
		(net "M_B_CPU1_SA_CA<5>")
	)
	(segment
		(start 87.517224 -253.604014)
		(end 87.502492 -253.595378)
		(width 0.088646)
		(layer "In2.Cu")
		(net "M_B_CPU1_SA_CA<5>")
	)
	(segment
		(start 89.382092 -253.595378)
		(end 89.381838 -253.595378)
		(width 0.088646)
		(layer "In2.Cu")
		(net "M_B_CPU1_SA_CA<5>")
	)
	(segment
		(start 51.686968 -261.916418)
		(end 51.090068 -261.916418)
		(width 0.18288)
		(layer "In2.Cu")
		(net "M_B_CPU1_SA_CA<5>")
	)
	(segment
		(start 86.577424 -253.604014)
		(end 86.562692 -253.595378)
		(width 0.088646)
		(layer "In2.Cu")
		(net "M_B_CPU1_SA_CA<5>")
	)
	(segment
		(start 61.616336 -258.228592)
		(end 61.616336 -258.822952)
		(width 0.18288)
		(layer "In2.Cu")
		(net "M_B_CPU1_SA_CA<5>")
	)
	(segment
		(start 55.095648 -259.981954)
		(end 55.095648 -260.375146)
		(width 0.18288)
		(layer "In2.Cu")
		(net "M_B_CPU1_SA_CA<5>")
	)
	(segment
		(start 56.615584 -259.813552)
		(end 56.34482 -259.542788)
		(width 0.18288)
		(layer "In2.Cu")
		(net "M_B_CPU1_SA_CA<5>")
	)
	(segment
		(start 79.784702 -256.242566)
		(end 72.827134 -256.242566)
		(width 0.18288)
		(layer "In2.Cu")
		(net "M_B_CPU1_SA_CA<5>")
	)
	(segment
		(start 64.798956 -258.44881)
		(end 64.425322 -258.075176)
		(width 0.18288)
		(layer "In2.Cu")
		(net "M_B_CPU1_SA_CA<5>")
	)
	(segment
		(start 52.22748 -261.482332)
		(end 52.045616 -261.55777)
		(width 0.18288)
		(layer "In2.Cu")
		(net "M_B_CPU1_SA_CA<5>")
	)
	(segment
		(start 69.260466 -257.341624)
		(end 68.90639 -257.871214)
		(width 0.18288)
		(layer "In2.Cu")
		(net "M_B_CPU1_SA_CA<5>")
	)
	(segment
		(start 56.34482 -259.542788)
		(end 55.534814 -259.542788)
		(width 0.18288)
		(layer "In2.Cu")
		(net "M_B_CPU1_SA_CA<5>")
	)
	(segment
		(start 65.6082 -258.068572)
		(end 65.227962 -258.44881)
		(width 0.18288)
		(layer "In2.Cu")
		(net "M_B_CPU1_SA_CA<5>")
	)
	(segment
		(start 65.227962 -258.44881)
		(end 64.798956 -258.44881)
		(width 0.18288)
		(layer "In2.Cu")
		(net "M_B_CPU1_SA_CA<5>")
	)
	(segment
		(start 85.637624 -253.604014)
		(end 85.622892 -253.595378)
		(width 0.088646)
		(layer "In2.Cu")
		(net "M_B_CPU1_SA_CA<5>")
	)
	(segment
		(start 54.338982 -261.332472)
		(end 54.123082 -261.548372)
		(width 0.18288)
		(layer "In2.Cu")
		(net "M_B_CPU1_SA_CA<5>")
	)
	(segment
		(start 61.616336 -258.822952)
		(end 61.456316 -258.982972)
		(width 0.18288)
		(layer "In2.Cu")
		(net "M_B_CPU1_SA_CA<5>")
	)
	(segment
		(start 51.090068 -261.916418)
		(end 51.089814 -261.916672)
		(width 0.18288)
		(layer "In2.Cu")
		(net "M_B_CPU1_SA_CA<5>")
	)
	(segment
		(start 60.493656 -258.816094)
		(end 60.493656 -258.30911)
		(width 0.18288)
		(layer "In2.Cu")
		(net "M_B_CPU1_SA_CA<5>")
	)
	(arc
		(start 87.128096 -253.595378)
		(mid 86.853897 -253.671213)
		(end 86.577424 -253.604014)
		(width 0.088646)
		(layer "In2.Cu")
		(net "M_B_CPU1_SA_CA<5>")
	)
	(arc
		(start 87.502492 -253.595378)
		(mid 87.315294 -253.545235)
		(end 87.128096 -253.595378)
		(width 0.088646)
		(layer "In2.Cu")
		(net "M_B_CPU1_SA_CA<5>")
	)
	(arc
		(start 86.562692 -253.595378)
		(mid 86.375494 -253.545235)
		(end 86.188296 -253.595378)
		(width 0.088646)
		(layer "In2.Cu")
		(net "M_B_CPU1_SA_CA<5>")
	)
	(arc
		(start 86.188296 -253.595378)
		(mid 85.914097 -253.671213)
		(end 85.637624 -253.604014)
		(width 0.088646)
		(layer "In2.Cu")
		(net "M_B_CPU1_SA_CA<5>")
	)
	(arc
		(start 88.442292 -253.595378)
		(mid 88.255094 -253.545235)
		(end 88.067896 -253.595378)
		(width 0.088646)
		(layer "In2.Cu")
		(net "M_B_CPU1_SA_CA<5>")
	)
	(arc
		(start 84.683092 -253.595378)
		(mid 84.621603 -253.554252)
		(end 84.565998 -253.505462)
		(width 0.088646)
		(layer "In2.Cu")
		(net "M_B_CPU1_SA_CA<5>")
	)
	(arc
		(start 89.381838 -253.595378)
		(mid 89.19475 -253.545201)
		(end 89.007696 -253.595378)
		(width 0.088646)
		(layer "In2.Cu")
		(net "M_B_CPU1_SA_CA<5>")
	)
	(arc
		(start 89.007696 -253.595378)
		(mid 88.733497 -253.671213)
		(end 88.457024 -253.604014)
		(width 0.088646)
		(layer "In2.Cu")
		(net "M_B_CPU1_SA_CA<5>")
	)
	(arc
		(start 85.248496 -253.595378)
		(mid 84.965938 -253.671027)
		(end 84.683346 -253.595378)
		(width 0.088646)
		(layer "In2.Cu")
		(net "M_B_CPU1_SA_CA<5>")
	)
	(arc
		(start 85.622892 -253.595378)
		(mid 85.435694 -253.545235)
		(end 85.248496 -253.595378)
		(width 0.088646)
		(layer "In2.Cu")
		(net "M_B_CPU1_SA_CA<5>")
	)
	(arc
		(start 88.067896 -253.595378)
		(mid 87.793697 -253.671213)
		(end 87.517224 -253.604014)
		(width 0.088646)
		(layer "In2.Cu")
		(net "M_B_CPU1_SA_CA<5>")
	)
	(segment
		(start 89.194894 -253.383796)
		(end 89.194894 -253.919736)
		(width 0.20066)
		(layer "F.Cu")
		(net "M_B_CPU1_SA_CA<4>")
	)
	(segment
		(start 40.520112 -262.495538)
		(end 40.520112 -262.823706)
		(width 0.20066)
		(layer "F.Cu")
		(net "M_B_CPU1_SA_CA<4>")
	)
	(segment
		(start 44.22013 -262.76681)
		(end 43.795188 -262.341868)
		(width 0.20066)
		(layer "F.Cu")
		(net "M_B_CPU1_SA_CA<4>")
	)
	(segment
		(start 41.3004 -262.341868)
		(end 41.29151 -262.332978)
		(width 0.1016)
		(layer "F.Cu")
		(net "M_B_CPU1_SA_CA<4>")
	)
	(segment
		(start 39.649908 -262.76681)
		(end 38.315646 -262.76681)
		(width 0.20066)
		(layer "F.Cu")
		(net "M_B_CPU1_SA_CA<4>")
	)
	(segment
		(start 43.795188 -262.341868)
		(end 43.616626 -262.341868)
		(width 0.20066)
		(layer "F.Cu")
		(net "M_B_CPU1_SA_CA<4>")
	)
	(segment
		(start 45.859446 -262.76681)
		(end 44.22013 -262.76681)
		(width 0.20066)
		(layer "F.Cu")
		(net "M_B_CPU1_SA_CA<4>")
	)
	(segment
		(start 43.285918 -262.341868)
		(end 41.3004 -262.341868)
		(width 0.1016)
		(layer "F.Cu")
		(net "M_B_CPU1_SA_CA<4>")
	)
	(segment
		(start 40.682672 -262.332978)
		(end 40.520112 -262.495538)
		(width 0.20066)
		(layer "F.Cu")
		(net "M_B_CPU1_SA_CA<4>")
	)
	(segment
		(start 43.616626 -262.341868)
		(end 43.285918 -262.341868)
		(width 0.101854)
		(layer "F.Cu")
		(net "M_B_CPU1_SA_CA<4>")
	)
	(segment
		(start 39.861236 -262.978138)
		(end 39.649908 -262.76681)
		(width 0.20066)
		(layer "F.Cu")
		(net "M_B_CPU1_SA_CA<4>")
	)
	(segment
		(start 46.964346 -262.76681)
		(end 45.859446 -262.76681)
		(width 0.20066)
		(layer "F.Cu")
		(net "M_B_CPU1_SA_CA<4>")
	)
	(segment
		(start 40.36568 -262.978138)
		(end 39.861236 -262.978138)
		(width 0.20066)
		(layer "F.Cu")
		(net "M_B_CPU1_SA_CA<4>")
	)
	(segment
		(start 40.520112 -262.823706)
		(end 40.36568 -262.978138)
		(width 0.20066)
		(layer "F.Cu")
		(net "M_B_CPU1_SA_CA<4>")
	)
	(segment
		(start 41.29151 -262.332978)
		(end 40.682672 -262.332978)
		(width 0.20066)
		(layer "F.Cu")
		(net "M_B_CPU1_SA_CA<4>")
	)
	(segment
		(start 51.33086 -262.425688)
		(end 51.246786 -262.341614)
		(width 0.18288)
		(layer "In2.Cu")
		(net "M_B_CPU1_SA_CA<4>")
	)
	(segment
		(start 67.587622 -258.972812)
		(end 64.255142 -258.972812)
		(width 0.18288)
		(layer "In2.Cu")
		(net "M_B_CPU1_SA_CA<4>")
	)
	(segment
		(start 61.933582 -259.313172)
		(end 61.933582 -259.559552)
		(width 0.18288)
		(layer "In2.Cu")
		(net "M_B_CPU1_SA_CA<4>")
	)
	(segment
		(start 83.876134 -253.982474)
		(end 82.533998 -253.982474)
		(width 0.18288)
		(layer "In2.Cu")
		(net "M_B_CPU1_SA_CA<4>")
	)
	(segment
		(start 50.30724 -262.341614)
		(end 50.146712 -262.502142)
		(width 0.18288)
		(layer "In2.Cu")
		(net "M_B_CPU1_SA_CA<4>")
	)
	(segment
		(start 51.246786 -262.341614)
		(end 50.30724 -262.341614)
		(width 0.18288)
		(layer "In2.Cu")
		(net "M_B_CPU1_SA_CA<4>")
	)
	(segment
		(start 88.470232 -254.227838)
		(end 88.442292 -254.244094)
		(width 0.088646)
		(layer "In2.Cu")
		(net "M_B_CPU1_SA_CA<4>")
	)
	(segment
		(start 62.416182 -259.084572)
		(end 62.162182 -259.084572)
		(width 0.18288)
		(layer "In2.Cu")
		(net "M_B_CPU1_SA_CA<4>")
	)
	(segment
		(start 47.53483 -262.196326)
		(end 46.964346 -262.76681)
		(width 0.18288)
		(layer "In2.Cu")
		(net "M_B_CPU1_SA_CA<4>")
	)
	(segment
		(start 49.07788 -262.196326)
		(end 47.53483 -262.196326)
		(width 0.18288)
		(layer "In2.Cu")
		(net "M_B_CPU1_SA_CA<4>")
	)
	(segment
		(start 49.547018 -262.985758)
		(end 49.386998 -262.825738)
		(width 0.18288)
		(layer "In2.Cu")
		(net "M_B_CPU1_SA_CA<4>")
	)
	(segment
		(start 73.344278 -256.588006)
		(end 72.653906 -256.87401)
		(width 0.18288)
		(layer "In2.Cu")
		(net "M_B_CPU1_SA_CA<4>")
	)
	(segment
		(start 79.928466 -256.588006)
		(end 73.344278 -256.588006)
		(width 0.18288)
		(layer "In2.Cu")
		(net "M_B_CPU1_SA_CA<4>")
	)
	(segment
		(start 59.463178 -259.512816)
		(end 58.387742 -260.588252)
		(width 0.18288)
		(layer "In2.Cu")
		(net "M_B_CPU1_SA_CA<4>")
	)
	(segment
		(start 84.008976 -253.982474)
		(end 83.876134 -253.982474)
		(width 0.088646)
		(layer "In2.Cu")
		(net "M_B_CPU1_SA_CA<4>")
	)
	(segment
		(start 49.98339 -262.985758)
		(end 49.547018 -262.985758)
		(width 0.18288)
		(layer "In2.Cu")
		(net "M_B_CPU1_SA_CA<4>")
	)
	(segment
		(start 59.808618 -259.512816)
		(end 59.463178 -259.512816)
		(width 0.18288)
		(layer "In2.Cu")
		(net "M_B_CPU1_SA_CA<4>")
	)
	(segment
		(start 61.759592 -259.733542)
		(end 60.029344 -259.733542)
		(width 0.18288)
		(layer "In2.Cu")
		(net "M_B_CPU1_SA_CA<4>")
	)
	(segment
		(start 62.162182 -259.084572)
		(end 61.933582 -259.313172)
		(width 0.18288)
		(layer "In2.Cu")
		(net "M_B_CPU1_SA_CA<4>")
	)
	(segment
		(start 84.495894 -254.29464)
		(end 84.321142 -254.29464)
		(width 0.088646)
		(layer "In2.Cu")
		(net "M_B_CPU1_SA_CA<4>")
	)
	(segment
		(start 54.93512 -261.266178)
		(end 54.93512 -262.151114)
		(width 0.18288)
		(layer "In2.Cu")
		(net "M_B_CPU1_SA_CA<4>")
	)
	(segment
		(start 52.018946 -262.425688)
		(end 51.33086 -262.425688)
		(width 0.18288)
		(layer "In2.Cu")
		(net "M_B_CPU1_SA_CA<4>")
	)
	(segment
		(start 58.387742 -260.588252)
		(end 55.613046 -260.588252)
		(width 0.18288)
		(layer "In2.Cu")
		(net "M_B_CPU1_SA_CA<4>")
	)
	(segment
		(start 52.083462 -262.361172)
		(end 52.018946 -262.425688)
		(width 0.18288)
		(layer "In2.Cu")
		(net "M_B_CPU1_SA_CA<4>")
	)
	(segment
		(start 50.146712 -262.502142)
		(end 50.146712 -262.822436)
		(width 0.18288)
		(layer "In2.Cu")
		(net "M_B_CPU1_SA_CA<4>")
	)
	(segment
		(start 63.99657 -259.231384)
		(end 62.562994 -259.231384)
		(width 0.18288)
		(layer "In2.Cu")
		(net "M_B_CPU1_SA_CA<4>")
	)
	(segment
		(start 49.386998 -262.505444)
		(end 49.07788 -262.196326)
		(width 0.18288)
		(layer "In2.Cu")
		(net "M_B_CPU1_SA_CA<4>")
	)
	(segment
		(start 50.146712 -262.822436)
		(end 49.98339 -262.985758)
		(width 0.18288)
		(layer "In2.Cu")
		(net "M_B_CPU1_SA_CA<4>")
	)
	(segment
		(start 84.321142 -254.29464)
		(end 84.008976 -253.982474)
		(width 0.088646)
		(layer "In2.Cu")
		(net "M_B_CPU1_SA_CA<4>")
	)
	(segment
		(start 55.613046 -260.588252)
		(end 54.93512 -261.266178)
		(width 0.18288)
		(layer "In2.Cu")
		(net "M_B_CPU1_SA_CA<4>")
	)
	(segment
		(start 54.725062 -262.361172)
		(end 52.083462 -262.361172)
		(width 0.18288)
		(layer "In2.Cu")
		(net "M_B_CPU1_SA_CA<4>")
	)
	(segment
		(start 89.194894 -253.919736)
		(end 88.470232 -254.227838)
		(width 0.088646)
		(layer "In2.Cu")
		(net "M_B_CPU1_SA_CA<4>")
	)
	(segment
		(start 54.93512 -262.151114)
		(end 54.725062 -262.361172)
		(width 0.18288)
		(layer "In2.Cu")
		(net "M_B_CPU1_SA_CA<4>")
	)
	(segment
		(start 49.386998 -262.825738)
		(end 49.386998 -262.505444)
		(width 0.18288)
		(layer "In2.Cu")
		(net "M_B_CPU1_SA_CA<4>")
	)
	(segment
		(start 72.653906 -256.87401)
		(end 67.587622 -258.972812)
		(width 0.18288)
		(layer "In2.Cu")
		(net "M_B_CPU1_SA_CA<4>")
	)
	(segment
		(start 62.562994 -259.231384)
		(end 62.416182 -259.084572)
		(width 0.18288)
		(layer "In2.Cu")
		(net "M_B_CPU1_SA_CA<4>")
	)
	(segment
		(start 60.029344 -259.733542)
		(end 59.808618 -259.512816)
		(width 0.18288)
		(layer "In2.Cu")
		(net "M_B_CPU1_SA_CA<4>")
	)
	(segment
		(start 82.533998 -253.982474)
		(end 79.928466 -256.588006)
		(width 0.18288)
		(layer "In2.Cu")
		(net "M_B_CPU1_SA_CA<4>")
	)
	(segment
		(start 61.933582 -259.559552)
		(end 61.759592 -259.733542)
		(width 0.18288)
		(layer "In2.Cu")
		(net "M_B_CPU1_SA_CA<4>")
	)
	(segment
		(start 64.255142 -258.972812)
		(end 63.99657 -259.231384)
		(width 0.18288)
		(layer "In2.Cu")
		(net "M_B_CPU1_SA_CA<4>")
	)
	(arc
		(start 88.067896 -254.244094)
		(mid 87.785194 -254.168318)
		(end 87.502492 -254.244094)
		(width 0.088646)
		(layer "In2.Cu")
		(net "M_B_CPU1_SA_CA<4>")
	)
	(arc
		(start 86.188296 -254.244094)
		(mid 85.905594 -254.168318)
		(end 85.622892 -254.244094)
		(width 0.088646)
		(layer "In2.Cu")
		(net "M_B_CPU1_SA_CA<4>")
	)
	(arc
		(start 85.622892 -254.244094)
		(mid 85.435694 -254.294237)
		(end 85.248496 -254.244094)
		(width 0.088646)
		(layer "In2.Cu")
		(net "M_B_CPU1_SA_CA<4>")
	)
	(arc
		(start 85.248496 -254.244094)
		(mid 84.965794 -254.168318)
		(end 84.683092 -254.244094)
		(width 0.088646)
		(layer "In2.Cu")
		(net "M_B_CPU1_SA_CA<4>")
	)
	(arc
		(start 86.562692 -254.244094)
		(mid 86.375494 -254.294237)
		(end 86.188296 -254.244094)
		(width 0.088646)
		(layer "In2.Cu")
		(net "M_B_CPU1_SA_CA<4>")
	)
	(arc
		(start 87.128096 -254.244094)
		(mid 86.845394 -254.168318)
		(end 86.562692 -254.244094)
		(width 0.088646)
		(layer "In2.Cu")
		(net "M_B_CPU1_SA_CA<4>")
	)
	(arc
		(start 84.683092 -254.244094)
		(mid 84.59282 -254.281693)
		(end 84.495894 -254.29464)
		(width 0.088646)
		(layer "In2.Cu")
		(net "M_B_CPU1_SA_CA<4>")
	)
	(arc
		(start 87.502492 -254.244094)
		(mid 87.315294 -254.294237)
		(end 87.128096 -254.244094)
		(width 0.088646)
		(layer "In2.Cu")
		(net "M_B_CPU1_SA_CA<4>")
	)
	(arc
		(start 88.442292 -254.244094)
		(mid 88.255094 -254.294237)
		(end 88.067896 -254.244094)
		(width 0.088646)
		(layer "In2.Cu")
		(net "M_B_CPU1_SA_CA<4>")
	)
	(segment
		(start 44.238926 -263.742678)
		(end 44.112942 -263.616694)
		(width 0.20066)
		(layer "F.Cu")
		(net "M_B_CPU1_SA_CA<3>")
	)
	(segment
		(start 44.112942 -263.616694)
		(end 42.415714 -263.616694)
		(width 0.20066)
		(layer "F.Cu")
		(net "M_B_CPU1_SA_CA<3>")
	)
	(segment
		(start 49.959514 -263.616694)
		(end 49.143412 -263.616694)
		(width 0.20066)
		(layer "F.Cu")
		(net "M_B_CPU1_SA_CA<3>")
	)
	(segment
		(start 48.935894 -263.824212)
		(end 48.489362 -263.824212)
		(width 0.20066)
		(layer "F.Cu")
		(net "M_B_CPU1_SA_CA<3>")
	)
	(segment
		(start 47.60468 -264.041636)
		(end 47.060358 -264.041636)
		(width 0.20066)
		(layer "F.Cu")
		(net "M_B_CPU1_SA_CA<3>")
	)
	(segment
		(start 44.735242 -264.05586)
		(end 44.38142 -264.05586)
		(width 0.20066)
		(layer "F.Cu")
		(net "M_B_CPU1_SA_CA<3>")
	)
	(segment
		(start 47.060358 -264.041636)
		(end 44.987464 -264.041636)
		(width 0.1016)
		(layer "F.Cu")
		(net "M_B_CPU1_SA_CA<3>")
	)
	(segment
		(start 44.238926 -263.913366)
		(end 44.238926 -263.742678)
		(width 0.20066)
		(layer "F.Cu")
		(net "M_B_CPU1_SA_CA<3>")
	)
	(segment
		(start 47.753778 -263.892538)
		(end 47.60468 -264.041636)
		(width 0.20066)
		(layer "F.Cu")
		(net "M_B_CPU1_SA_CA<3>")
	)
	(segment
		(start 48.489362 -263.824212)
		(end 48.277526 -263.612376)
		(width 0.20066)
		(layer "F.Cu")
		(net "M_B_CPU1_SA_CA<3>")
	)
	(segment
		(start 90.604848 -254.197612)
		(end 90.604848 -254.733298)
		(width 0.20066)
		(layer "F.Cu")
		(net "M_B_CPU1_SA_CA<3>")
	)
	(segment
		(start 90.604848 -254.733298)
		(end 90.604594 -254.733552)
		(width 0.20066)
		(layer "F.Cu")
		(net "M_B_CPU1_SA_CA<3>")
	)
	(segment
		(start 49.143412 -263.616694)
		(end 48.935894 -263.824212)
		(width 0.20066)
		(layer "F.Cu")
		(net "M_B_CPU1_SA_CA<3>")
	)
	(segment
		(start 44.38142 -264.05586)
		(end 44.238926 -263.913366)
		(width 0.20066)
		(layer "F.Cu")
		(net "M_B_CPU1_SA_CA<3>")
	)
	(segment
		(start 48.277526 -263.612376)
		(end 47.882302 -263.612376)
		(width 0.20066)
		(layer "F.Cu")
		(net "M_B_CPU1_SA_CA<3>")
	)
	(segment
		(start 44.749466 -264.041636)
		(end 44.735242 -264.05586)
		(width 0.101854)
		(layer "F.Cu")
		(net "M_B_CPU1_SA_CA<3>")
	)
	(segment
		(start 51.089814 -263.616694)
		(end 49.959514 -263.616694)
		(width 0.20066)
		(layer "F.Cu")
		(net "M_B_CPU1_SA_CA<3>")
	)
	(segment
		(start 47.753778 -263.7409)
		(end 47.753778 -263.892538)
		(width 0.20066)
		(layer "F.Cu")
		(net "M_B_CPU1_SA_CA<3>")
	)
	(segment
		(start 47.882302 -263.612376)
		(end 47.753778 -263.7409)
		(width 0.20066)
		(layer "F.Cu")
		(net "M_B_CPU1_SA_CA<3>")
	)
	(segment
		(start 44.987464 -264.041636)
		(end 44.749466 -264.041636)
		(width 0.101854)
		(layer "F.Cu")
		(net "M_B_CPU1_SA_CA<3>")
	)
	(segment
		(start 84.381848 -254.659892)
		(end 84.176362 -254.659892)
		(width 0.088646)
		(layer "In2.Cu")
		(net "M_B_CPU1_SA_CA<3>")
	)
	(segment
		(start 57.25541 -261.099554)
		(end 57.13349 -261.221474)
		(width 0.18288)
		(layer "In2.Cu")
		(net "M_B_CPU1_SA_CA<3>")
	)
	(segment
		(start 61.002418 -260.241542)
		(end 60.421266 -260.241542)
		(width 0.18288)
		(layer "In2.Cu")
		(net "M_B_CPU1_SA_CA<3>")
	)
	(segment
		(start 64.118998 -259.805932)
		(end 63.815468 -260.109462)
		(width 0.18288)
		(layer "In2.Cu")
		(net "M_B_CPU1_SA_CA<3>")
	)
	(segment
		(start 53.12791 -263.578848)
		(end 53.002434 -263.453372)
		(width 0.18288)
		(layer "In2.Cu")
		(net "M_B_CPU1_SA_CA<3>")
	)
	(segment
		(start 59.470036 -260.650228)
		(end 59.219592 -260.650228)
		(width 0.18288)
		(layer "In2.Cu")
		(net "M_B_CPU1_SA_CA<3>")
	)
	(segment
		(start 57.85739 -261.221474)
		(end 57.73547 -261.099554)
		(width 0.18288)
		(layer "In2.Cu")
		(net "M_B_CPU1_SA_CA<3>")
	)
	(segment
		(start 60.28817 -260.374638)
		(end 60.28817 -260.558534)
		(width 0.18288)
		(layer "In2.Cu")
		(net "M_B_CPU1_SA_CA<3>")
	)
	(segment
		(start 62.478666 -260.393688)
		(end 62.228984 -260.64337)
		(width 0.18288)
		(layer "In2.Cu")
		(net "M_B_CPU1_SA_CA<3>")
	)
	(segment
		(start 57.85739 -261.388352)
		(end 57.85739 -261.221474)
		(width 0.18288)
		(layer "In2.Cu")
		(net "M_B_CPU1_SA_CA<3>")
	)
	(segment
		(start 52.842414 -263.1694)
		(end 52.54371 -263.1694)
		(width 0.18288)
		(layer "In2.Cu")
		(net "M_B_CPU1_SA_CA<3>")
	)
	(segment
		(start 66.14287 -259.490464)
		(end 65.827402 -259.805932)
		(width 0.18288)
		(layer "In2.Cu")
		(net "M_B_CPU1_SA_CA<3>")
	)
	(segment
		(start 59.034934 -260.834886)
		(end 59.034934 -261.357872)
		(width 0.18288)
		(layer "In2.Cu")
		(net "M_B_CPU1_SA_CA<3>")
	)
	(segment
		(start 56.996838 -261.528306)
		(end 56.68772 -261.528306)
		(width 0.18288)
		(layer "In2.Cu")
		(net "M_B_CPU1_SA_CA<3>")
	)
	(segment
		(start 66.69278 -259.805932)
		(end 66.377312 -259.490464)
		(width 0.18288)
		(layer "In2.Cu")
		(net "M_B_CPU1_SA_CA<3>")
	)
	(segment
		(start 51.089814 -263.365234)
		(end 51.089814 -263.616694)
		(width 0.18288)
		(layer "In2.Cu")
		(net "M_B_CPU1_SA_CA<3>")
	)
	(segment
		(start 58.01741 -261.548372)
		(end 57.85739 -261.388352)
		(width 0.18288)
		(layer "In2.Cu")
		(net "M_B_CPU1_SA_CA<3>")
	)
	(segment
		(start 73.857866 -256.933446)
		(end 73.048622 -257.268726)
		(width 0.18288)
		(layer "In2.Cu")
		(net "M_B_CPU1_SA_CA<3>")
	)
	(segment
		(start 55.158132 -262.802116)
		(end 54.837076 -263.123172)
		(width 0.18288)
		(layer "In2.Cu")
		(net "M_B_CPU1_SA_CA<3>")
	)
	(segment
		(start 53.002434 -263.453372)
		(end 53.002434 -263.32942)
		(width 0.18288)
		(layer "In2.Cu")
		(net "M_B_CPU1_SA_CA<3>")
	)
	(segment
		(start 84.001356 -254.484886)
		(end 83.876134 -254.484886)
		(width 0.088646)
		(layer "In2.Cu")
		(net "M_B_CPU1_SA_CA<3>")
	)
	(segment
		(start 63.415418 -260.109462)
		(end 63.05169 -259.745734)
		(width 0.18288)
		(layer "In2.Cu")
		(net "M_B_CPU1_SA_CA<3>")
	)
	(segment
		(start 55.44947 -261.53999)
		(end 55.44947 -262.373618)
		(width 0.18288)
		(layer "In2.Cu")
		(net "M_B_CPU1_SA_CA<3>")
	)
	(segment
		(start 62.478666 -259.998972)
		(end 62.478666 -260.393688)
		(width 0.18288)
		(layer "In2.Cu")
		(net "M_B_CPU1_SA_CA<3>")
	)
	(segment
		(start 73.048622 -257.268726)
		(end 66.92265 -259.805932)
		(width 0.18288)
		(layer "In2.Cu")
		(net "M_B_CPU1_SA_CA<3>")
	)
	(segment
		(start 55.44947 -262.373618)
		(end 55.158132 -262.664956)
		(width 0.18288)
		(layer "In2.Cu")
		(net "M_B_CPU1_SA_CA<3>")
	)
	(segment
		(start 55.158132 -262.664956)
		(end 55.158132 -262.802116)
		(width 0.18288)
		(layer "In2.Cu")
		(net "M_B_CPU1_SA_CA<3>")
	)
	(segment
		(start 90.604594 -254.733552)
		(end 89.879932 -254.42545)
		(width 0.088646)
		(layer "In2.Cu")
		(net "M_B_CPU1_SA_CA<3>")
	)
	(segment
		(start 84.56041 -254.48133)
		(end 84.381848 -254.659892)
		(width 0.088646)
		(layer "In2.Cu")
		(net "M_B_CPU1_SA_CA<3>")
	)
	(segment
		(start 63.815468 -260.109462)
		(end 63.415418 -260.109462)
		(width 0.18288)
		(layer "In2.Cu")
		(net "M_B_CPU1_SA_CA<3>")
	)
	(segment
		(start 66.92265 -259.805932)
		(end 66.69278 -259.805932)
		(width 0.18288)
		(layer "In2.Cu")
		(net "M_B_CPU1_SA_CA<3>")
	)
	(segment
		(start 89.879932 -254.42545)
		(end 89.851992 -254.409194)
		(width 0.088646)
		(layer "In2.Cu")
		(net "M_B_CPU1_SA_CA<3>")
	)
	(segment
		(start 57.13349 -261.391654)
		(end 56.996838 -261.528306)
		(width 0.18288)
		(layer "In2.Cu")
		(net "M_B_CPU1_SA_CA<3>")
	)
	(segment
		(start 62.731904 -259.745734)
		(end 62.478666 -259.998972)
		(width 0.18288)
		(layer "In2.Cu")
		(net "M_B_CPU1_SA_CA<3>")
	)
	(segment
		(start 66.377312 -259.490464)
		(end 66.14287 -259.490464)
		(width 0.18288)
		(layer "In2.Cu")
		(net "M_B_CPU1_SA_CA<3>")
	)
	(segment
		(start 53.002434 -263.32942)
		(end 52.842414 -263.1694)
		(width 0.18288)
		(layer "In2.Cu")
		(net "M_B_CPU1_SA_CA<3>")
	)
	(segment
		(start 53.584348 -263.578848)
		(end 53.12791 -263.578848)
		(width 0.18288)
		(layer "In2.Cu")
		(net "M_B_CPU1_SA_CA<3>")
	)
	(segment
		(start 52.54371 -263.1694)
		(end 52.317396 -262.943086)
		(width 0.18288)
		(layer "In2.Cu")
		(net "M_B_CPU1_SA_CA<3>")
	)
	(segment
		(start 63.05169 -259.745734)
		(end 62.731904 -259.745734)
		(width 0.18288)
		(layer "In2.Cu")
		(net "M_B_CPU1_SA_CA<3>")
	)
	(segment
		(start 84.176362 -254.659892)
		(end 84.001356 -254.484886)
		(width 0.088646)
		(layer "In2.Cu")
		(net "M_B_CPU1_SA_CA<3>")
	)
	(segment
		(start 55.660544 -261.328916)
		(end 55.44947 -261.53999)
		(width 0.18288)
		(layer "In2.Cu")
		(net "M_B_CPU1_SA_CA<3>")
	)
	(segment
		(start 54.837076 -263.123172)
		(end 53.869844 -263.123172)
		(width 0.18288)
		(layer "In2.Cu")
		(net "M_B_CPU1_SA_CA<3>")
	)
	(segment
		(start 61.404246 -260.64337)
		(end 61.002418 -260.241542)
		(width 0.18288)
		(layer "In2.Cu")
		(net "M_B_CPU1_SA_CA<3>")
	)
	(segment
		(start 59.034934 -261.357872)
		(end 58.844434 -261.548372)
		(width 0.18288)
		(layer "In2.Cu")
		(net "M_B_CPU1_SA_CA<3>")
	)
	(segment
		(start 57.13349 -261.221474)
		(end 57.13349 -261.391654)
		(width 0.18288)
		(layer "In2.Cu")
		(net "M_B_CPU1_SA_CA<3>")
	)
	(segment
		(start 56.68772 -261.528306)
		(end 56.537352 -261.678674)
		(width 0.18288)
		(layer "In2.Cu")
		(net "M_B_CPU1_SA_CA<3>")
	)
	(segment
		(start 56.23687 -261.678674)
		(end 55.887112 -261.328916)
		(width 0.18288)
		(layer "In2.Cu")
		(net "M_B_CPU1_SA_CA<3>")
	)
	(segment
		(start 60.28817 -260.558534)
		(end 59.930538 -260.916166)
		(width 0.18288)
		(layer "In2.Cu")
		(net "M_B_CPU1_SA_CA<3>")
	)
	(segment
		(start 53.709824 -263.453372)
		(end 53.584348 -263.578848)
		(width 0.18288)
		(layer "In2.Cu")
		(net "M_B_CPU1_SA_CA<3>")
	)
	(segment
		(start 52.317396 -262.943086)
		(end 51.511962 -262.943086)
		(width 0.18288)
		(layer "In2.Cu")
		(net "M_B_CPU1_SA_CA<3>")
	)
	(segment
		(start 82.52079 -254.484886)
		(end 80.07223 -256.933446)
		(width 0.18288)
		(layer "In2.Cu")
		(net "M_B_CPU1_SA_CA<3>")
	)
	(segment
		(start 59.930538 -260.916166)
		(end 59.735974 -260.916166)
		(width 0.18288)
		(layer "In2.Cu")
		(net "M_B_CPU1_SA_CA<3>")
	)
	(segment
		(start 59.735974 -260.916166)
		(end 59.470036 -260.650228)
		(width 0.18288)
		(layer "In2.Cu")
		(net "M_B_CPU1_SA_CA<3>")
	)
	(segment
		(start 65.827402 -259.805932)
		(end 64.118998 -259.805932)
		(width 0.18288)
		(layer "In2.Cu")
		(net "M_B_CPU1_SA_CA<3>")
	)
	(segment
		(start 53.869844 -263.123172)
		(end 53.709824 -263.283192)
		(width 0.18288)
		(layer "In2.Cu")
		(net "M_B_CPU1_SA_CA<3>")
	)
	(segment
		(start 57.73547 -261.099554)
		(end 57.25541 -261.099554)
		(width 0.18288)
		(layer "In2.Cu")
		(net "M_B_CPU1_SA_CA<3>")
	)
	(segment
		(start 56.537352 -261.678674)
		(end 56.23687 -261.678674)
		(width 0.18288)
		(layer "In2.Cu")
		(net "M_B_CPU1_SA_CA<3>")
	)
	(segment
		(start 80.07223 -256.933446)
		(end 73.857866 -256.933446)
		(width 0.18288)
		(layer "In2.Cu")
		(net "M_B_CPU1_SA_CA<3>")
	)
	(segment
		(start 58.844434 -261.548372)
		(end 58.01741 -261.548372)
		(width 0.18288)
		(layer "In2.Cu")
		(net "M_B_CPU1_SA_CA<3>")
	)
	(segment
		(start 60.421266 -260.241542)
		(end 60.28817 -260.374638)
		(width 0.18288)
		(layer "In2.Cu")
		(net "M_B_CPU1_SA_CA<3>")
	)
	(segment
		(start 53.709824 -263.283192)
		(end 53.709824 -263.453372)
		(width 0.18288)
		(layer "In2.Cu")
		(net "M_B_CPU1_SA_CA<3>")
	)
	(segment
		(start 51.511962 -262.943086)
		(end 51.089814 -263.365234)
		(width 0.18288)
		(layer "In2.Cu")
		(net "M_B_CPU1_SA_CA<3>")
	)
	(segment
		(start 59.219592 -260.650228)
		(end 59.034934 -260.834886)
		(width 0.18288)
		(layer "In2.Cu")
		(net "M_B_CPU1_SA_CA<3>")
	)
	(segment
		(start 83.876134 -254.484886)
		(end 82.52079 -254.484886)
		(width 0.18288)
		(layer "In2.Cu")
		(net "M_B_CPU1_SA_CA<3>")
	)
	(segment
		(start 55.887112 -261.328916)
		(end 55.660544 -261.328916)
		(width 0.18288)
		(layer "In2.Cu")
		(net "M_B_CPU1_SA_CA<3>")
	)
	(segment
		(start 62.228984 -260.64337)
		(end 61.404246 -260.64337)
		(width 0.18288)
		(layer "In2.Cu")
		(net "M_B_CPU1_SA_CA<3>")
	)
	(arc
		(start 87.972392 -254.409194)
		(mid 87.785194 -254.359051)
		(end 87.597996 -254.409194)
		(width 0.088646)
		(layer "In2.Cu")
		(net "M_B_CPU1_SA_CA<3>")
	)
	(arc
		(start 86.658196 -254.409194)
		(mid 86.375494 -254.48497)
		(end 86.092792 -254.409194)
		(width 0.088646)
		(layer "In2.Cu")
		(net "M_B_CPU1_SA_CA<3>")
	)
	(arc
		(start 87.032592 -254.409194)
		(mid 86.845394 -254.359051)
		(end 86.658196 -254.409194)
		(width 0.088646)
		(layer "In2.Cu")
		(net "M_B_CPU1_SA_CA<3>")
	)
	(arc
		(start 84.778596 -254.409194)
		(mid 84.673202 -254.45644)
		(end 84.56041 -254.48133)
		(width 0.088646)
		(layer "In2.Cu")
		(net "M_B_CPU1_SA_CA<3>")
	)
	(arc
		(start 88.537796 -254.409194)
		(mid 88.255094 -254.48497)
		(end 87.972392 -254.409194)
		(width 0.088646)
		(layer "In2.Cu")
		(net "M_B_CPU1_SA_CA<3>")
	)
	(arc
		(start 86.092792 -254.409194)
		(mid 85.905594 -254.359051)
		(end 85.718396 -254.409194)
		(width 0.088646)
		(layer "In2.Cu")
		(net "M_B_CPU1_SA_CA<3>")
	)
	(arc
		(start 88.912192 -254.409194)
		(mid 88.724994 -254.359051)
		(end 88.537796 -254.409194)
		(width 0.088646)
		(layer "In2.Cu")
		(net "M_B_CPU1_SA_CA<3>")
	)
	(arc
		(start 89.477596 -254.409194)
		(mid 89.194894 -254.48497)
		(end 88.912192 -254.409194)
		(width 0.088646)
		(layer "In2.Cu")
		(net "M_B_CPU1_SA_CA<3>")
	)
	(arc
		(start 87.597996 -254.409194)
		(mid 87.315294 -254.48497)
		(end 87.032592 -254.409194)
		(width 0.088646)
		(layer "In2.Cu")
		(net "M_B_CPU1_SA_CA<3>")
	)
	(arc
		(start 89.851992 -254.409194)
		(mid 89.664794 -254.359051)
		(end 89.477596 -254.409194)
		(width 0.088646)
		(layer "In2.Cu")
		(net "M_B_CPU1_SA_CA<3>")
	)
	(arc
		(start 85.152992 -254.409194)
		(mid 84.965794 -254.359051)
		(end 84.778596 -254.409194)
		(width 0.088646)
		(layer "In2.Cu")
		(net "M_B_CPU1_SA_CA<3>")
	)
	(arc
		(start 85.718396 -254.409194)
		(mid 85.435694 -254.48497)
		(end 85.152992 -254.409194)
		(width 0.088646)
		(layer "In2.Cu")
		(net "M_B_CPU1_SA_CA<3>")
	)
	(segment
		(start 88.725248 -254.733298)
		(end 88.724994 -254.733552)
		(width 0.20066)
		(layer "F.Cu")
		(net "M_B_CPU1_SA_CA<2>")
	)
	(segment
		(start 46.964346 -264.466578)
		(end 45.859446 -264.466578)
		(width 0.20066)
		(layer "F.Cu")
		(net "M_B_CPU1_SA_CA<2>")
	)
	(segment
		(start 40.36568 -264.677906)
		(end 39.861236 -264.677906)
		(width 0.20066)
		(layer "F.Cu")
		(net "M_B_CPU1_SA_CA<2>")
	)
	(segment
		(start 45.859446 -264.466578)
		(end 44.22013 -264.466578)
		(width 0.20066)
		(layer "F.Cu")
		(net "M_B_CPU1_SA_CA<2>")
	)
	(segment
		(start 44.22013 -264.466578)
		(end 43.795188 -264.041636)
		(width 0.20066)
		(layer "F.Cu")
		(net "M_B_CPU1_SA_CA<2>")
	)
	(segment
		(start 43.795188 -264.041636)
		(end 43.616626 -264.041636)
		(width 0.20066)
		(layer "F.Cu")
		(net "M_B_CPU1_SA_CA<2>")
	)
	(segment
		(start 39.649908 -264.466578)
		(end 38.315646 -264.466578)
		(width 0.20066)
		(layer "F.Cu")
		(net "M_B_CPU1_SA_CA<2>")
	)
	(segment
		(start 43.285918 -264.041636)
		(end 41.3004 -264.041636)
		(width 0.1016)
		(layer "F.Cu")
		(net "M_B_CPU1_SA_CA<2>")
	)
	(segment
		(start 40.682672 -264.032746)
		(end 40.520112 -264.195306)
		(width 0.20066)
		(layer "F.Cu")
		(net "M_B_CPU1_SA_CA<2>")
	)
	(segment
		(start 40.520112 -264.195306)
		(end 40.520112 -264.523474)
		(width 0.20066)
		(layer "F.Cu")
		(net "M_B_CPU1_SA_CA<2>")
	)
	(segment
		(start 41.29151 -264.032746)
		(end 40.682672 -264.032746)
		(width 0.20066)
		(layer "F.Cu")
		(net "M_B_CPU1_SA_CA<2>")
	)
	(segment
		(start 41.3004 -264.041636)
		(end 41.29151 -264.032746)
		(width 0.1016)
		(layer "F.Cu")
		(net "M_B_CPU1_SA_CA<2>")
	)
	(segment
		(start 39.861236 -264.677906)
		(end 39.649908 -264.466578)
		(width 0.20066)
		(layer "F.Cu")
		(net "M_B_CPU1_SA_CA<2>")
	)
	(segment
		(start 43.616626 -264.041636)
		(end 43.285918 -264.041636)
		(width 0.101854)
		(layer "F.Cu")
		(net "M_B_CPU1_SA_CA<2>")
	)
	(segment
		(start 40.520112 -264.523474)
		(end 40.36568 -264.677906)
		(width 0.20066)
		(layer "F.Cu")
		(net "M_B_CPU1_SA_CA<2>")
	)
	(segment
		(start 88.725248 -254.197612)
		(end 88.725248 -254.733298)
		(width 0.20066)
		(layer "F.Cu")
		(net "M_B_CPU1_SA_CA<2>")
	)
	(segment
		(start 84.495894 -254.982218)
		(end 84.112354 -254.982218)
		(width 0.088646)
		(layer "In2.Cu")
		(net "M_B_CPU1_SA_CA<2>")
	)
	(segment
		(start 83.876134 -254.894588)
		(end 82.600292 -254.894588)
		(width 0.18288)
		(layer "In2.Cu")
		(net "M_B_CPU1_SA_CA<2>")
	)
	(segment
		(start 61.80963 -261.469124)
		(end 59.65571 -261.469124)
		(width 0.18288)
		(layer "In2.Cu")
		(net "M_B_CPU1_SA_CA<2>")
	)
	(segment
		(start 59.65571 -261.469124)
		(end 58.807096 -262.317738)
		(width 0.18288)
		(layer "In2.Cu")
		(net "M_B_CPU1_SA_CA<2>")
	)
	(segment
		(start 62.962282 -260.628892)
		(end 62.394084 -261.19709)
		(width 0.18288)
		(layer "In2.Cu")
		(net "M_B_CPU1_SA_CA<2>")
	)
	(segment
		(start 84.024724 -254.894588)
		(end 83.876134 -254.894588)
		(width 0.088646)
		(layer "In2.Cu")
		(net "M_B_CPU1_SA_CA<2>")
	)
	(segment
		(start 48.427894 -263.09955)
		(end 48.2346 -262.906256)
		(width 0.18288)
		(layer "In2.Cu")
		(net "M_B_CPU1_SA_CA<2>")
	)
	(segment
		(start 48.427894 -263.750552)
		(end 48.427894 -263.09955)
		(width 0.18288)
		(layer "In2.Cu")
		(net "M_B_CPU1_SA_CA<2>")
	)
	(segment
		(start 58.807096 -262.317738)
		(end 56.22163 -262.317738)
		(width 0.18288)
		(layer "In2.Cu")
		(net "M_B_CPU1_SA_CA<2>")
	)
	(segment
		(start 66.837814 -260.397498)
		(end 66.01841 -260.397498)
		(width 0.18288)
		(layer "In2.Cu")
		(net "M_B_CPU1_SA_CA<2>")
	)
	(segment
		(start 62.394084 -261.19709)
		(end 62.081664 -261.19709)
		(width 0.18288)
		(layer "In2.Cu")
		(net "M_B_CPU1_SA_CA<2>")
	)
	(segment
		(start 49.093882 -263.910572)
		(end 48.587914 -263.910572)
		(width 0.18288)
		(layer "In2.Cu")
		(net "M_B_CPU1_SA_CA<2>")
	)
	(segment
		(start 84.112354 -254.982218)
		(end 84.024724 -254.894588)
		(width 0.088646)
		(layer "In2.Cu")
		(net "M_B_CPU1_SA_CA<2>")
	)
	(segment
		(start 55.87238 -262.861298)
		(end 54.645306 -264.088372)
		(width 0.18288)
		(layer "In2.Cu")
		(net "M_B_CPU1_SA_CA<2>")
	)
	(segment
		(start 82.600292 -254.894588)
		(end 80.215994 -257.278886)
		(width 0.18288)
		(layer "In2.Cu")
		(net "M_B_CPU1_SA_CA<2>")
	)
	(segment
		(start 51.615086 -263.826244)
		(end 51.399694 -264.041636)
		(width 0.18288)
		(layer "In2.Cu")
		(net "M_B_CPU1_SA_CA<2>")
	)
	(segment
		(start 47.680372 -263.750552)
		(end 46.964346 -264.466578)
		(width 0.18288)
		(layer "In2.Cu")
		(net "M_B_CPU1_SA_CA<2>")
	)
	(segment
		(start 51.88839 -263.826244)
		(end 51.615086 -263.826244)
		(width 0.18288)
		(layer "In2.Cu")
		(net "M_B_CPU1_SA_CA<2>")
	)
	(segment
		(start 80.215994 -257.278886)
		(end 74.371708 -257.278886)
		(width 0.18288)
		(layer "In2.Cu")
		(net "M_B_CPU1_SA_CA<2>")
	)
	(segment
		(start 47.680372 -263.066276)
		(end 47.680372 -263.750552)
		(width 0.18288)
		(layer "In2.Cu")
		(net "M_B_CPU1_SA_CA<2>")
	)
	(segment
		(start 88.724994 -254.733552)
		(end 88.001094 -255.0414)
		(width 0.088646)
		(layer "In2.Cu")
		(net "M_B_CPU1_SA_CA<2>")
	)
	(segment
		(start 62.081664 -261.19709)
		(end 61.80963 -261.469124)
		(width 0.18288)
		(layer "In2.Cu")
		(net "M_B_CPU1_SA_CA<2>")
	)
	(segment
		(start 88.001094 -255.0414)
		(end 87.972392 -255.058164)
		(width 0.088646)
		(layer "In2.Cu")
		(net "M_B_CPU1_SA_CA<2>")
	)
	(segment
		(start 49.652682 -264.469372)
		(end 49.093882 -263.910572)
		(width 0.18288)
		(layer "In2.Cu")
		(net "M_B_CPU1_SA_CA<2>")
	)
	(segment
		(start 87.972392 -255.058164)
		(end 87.972392 -255.05791)
		(width 0.088646)
		(layer "In2.Cu")
		(net "M_B_CPU1_SA_CA<2>")
	)
	(segment
		(start 55.87238 -262.666988)
		(end 55.87238 -262.861298)
		(width 0.18288)
		(layer "In2.Cu")
		(net "M_B_CPU1_SA_CA<2>")
	)
	(segment
		(start 48.2346 -262.906256)
		(end 47.840392 -262.906256)
		(width 0.18288)
		(layer "In2.Cu")
		(net "M_B_CPU1_SA_CA<2>")
	)
	(segment
		(start 65.787016 -260.628892)
		(end 62.962282 -260.628892)
		(width 0.18288)
		(layer "In2.Cu")
		(net "M_B_CPU1_SA_CA<2>")
	)
	(segment
		(start 66.01841 -260.397498)
		(end 65.787016 -260.628892)
		(width 0.18288)
		(layer "In2.Cu")
		(net "M_B_CPU1_SA_CA<2>")
	)
	(segment
		(start 50.122328 -264.469372)
		(end 49.652682 -264.469372)
		(width 0.18288)
		(layer "In2.Cu")
		(net "M_B_CPU1_SA_CA<2>")
	)
	(segment
		(start 54.645306 -264.088372)
		(end 52.150518 -264.088372)
		(width 0.18288)
		(layer "In2.Cu")
		(net "M_B_CPU1_SA_CA<2>")
	)
	(segment
		(start 48.587914 -263.910572)
		(end 48.427894 -263.750552)
		(width 0.18288)
		(layer "In2.Cu")
		(net "M_B_CPU1_SA_CA<2>")
	)
	(segment
		(start 74.371708 -257.278886)
		(end 73.443084 -257.663188)
		(width 0.18288)
		(layer "In2.Cu")
		(net "M_B_CPU1_SA_CA<2>")
	)
	(segment
		(start 56.22163 -262.317738)
		(end 55.87238 -262.666988)
		(width 0.18288)
		(layer "In2.Cu")
		(net "M_B_CPU1_SA_CA<2>")
	)
	(segment
		(start 52.150518 -264.088372)
		(end 51.88839 -263.826244)
		(width 0.18288)
		(layer "In2.Cu")
		(net "M_B_CPU1_SA_CA<2>")
	)
	(segment
		(start 73.443084 -257.663188)
		(end 66.837814 -260.397498)
		(width 0.18288)
		(layer "In2.Cu")
		(net "M_B_CPU1_SA_CA<2>")
	)
	(segment
		(start 50.550064 -264.041636)
		(end 50.122328 -264.469372)
		(width 0.18288)
		(layer "In2.Cu")
		(net "M_B_CPU1_SA_CA<2>")
	)
	(segment
		(start 47.840392 -262.906256)
		(end 47.680372 -263.066276)
		(width 0.18288)
		(layer "In2.Cu")
		(net "M_B_CPU1_SA_CA<2>")
	)
	(segment
		(start 51.399694 -264.041636)
		(end 50.550064 -264.041636)
		(width 0.18288)
		(layer "In2.Cu")
		(net "M_B_CPU1_SA_CA<2>")
	)
	(arc
		(start 84.778596 -255.05791)
		(mid 84.64223 -255.001432)
		(end 84.495894 -254.982218)
		(width 0.088646)
		(layer "In2.Cu")
		(net "M_B_CPU1_SA_CA<2>")
	)
	(arc
		(start 87.597996 -255.05791)
		(mid 87.315294 -254.982168)
		(end 87.032592 -255.05791)
		(width 0.088646)
		(layer "In2.Cu")
		(net "M_B_CPU1_SA_CA<2>")
	)
	(arc
		(start 87.032592 -255.05791)
		(mid 86.845394 -255.108053)
		(end 86.658196 -255.05791)
		(width 0.088646)
		(layer "In2.Cu")
		(net "M_B_CPU1_SA_CA<2>")
	)
	(arc
		(start 87.972392 -255.05791)
		(mid 87.785194 -255.108053)
		(end 87.597996 -255.05791)
		(width 0.088646)
		(layer "In2.Cu")
		(net "M_B_CPU1_SA_CA<2>")
	)
	(arc
		(start 86.092792 -255.05791)
		(mid 85.905594 -255.108053)
		(end 85.718396 -255.05791)
		(width 0.088646)
		(layer "In2.Cu")
		(net "M_B_CPU1_SA_CA<2>")
	)
	(arc
		(start 86.658196 -255.05791)
		(mid 86.375494 -254.982168)
		(end 86.092792 -255.05791)
		(width 0.088646)
		(layer "In2.Cu")
		(net "M_B_CPU1_SA_CA<2>")
	)
	(arc
		(start 85.152992 -255.05791)
		(mid 84.965794 -255.108053)
		(end 84.778596 -255.05791)
		(width 0.088646)
		(layer "In2.Cu")
		(net "M_B_CPU1_SA_CA<2>")
	)
	(arc
		(start 85.718396 -255.05791)
		(mid 85.435694 -254.982168)
		(end 85.152992 -255.05791)
		(width 0.088646)
		(layer "In2.Cu")
		(net "M_B_CPU1_SA_CA<2>")
	)
	(segment
		(start 48.935894 -265.524234)
		(end 48.489362 -265.524234)
		(width 0.20066)
		(layer "F.Cu")
		(net "M_B_CPU1_SA_CA<1>")
	)
	(segment
		(start 49.143412 -265.316716)
		(end 48.935894 -265.524234)
		(width 0.20066)
		(layer "F.Cu")
		(net "M_B_CPU1_SA_CA<1>")
	)
	(segment
		(start 44.749466 -265.741658)
		(end 44.735242 -265.755882)
		(width 0.101854)
		(layer "F.Cu")
		(net "M_B_CPU1_SA_CA<1>")
	)
	(segment
		(start 91.074494 -255.011682)
		(end 91.074494 -255.547368)
		(width 0.20066)
		(layer "F.Cu")
		(net "M_B_CPU1_SA_CA<1>")
	)
	(segment
		(start 48.277526 -265.312398)
		(end 47.882302 -265.312398)
		(width 0.20066)
		(layer "F.Cu")
		(net "M_B_CPU1_SA_CA<1>")
	)
	(segment
		(start 44.38142 -265.755882)
		(end 44.238926 -265.613388)
		(width 0.20066)
		(layer "F.Cu")
		(net "M_B_CPU1_SA_CA<1>")
	)
	(segment
		(start 47.753778 -265.59256)
		(end 47.60468 -265.741658)
		(width 0.20066)
		(layer "F.Cu")
		(net "M_B_CPU1_SA_CA<1>")
	)
	(segment
		(start 48.489362 -265.524234)
		(end 48.277526 -265.312398)
		(width 0.20066)
		(layer "F.Cu")
		(net "M_B_CPU1_SA_CA<1>")
	)
	(segment
		(start 47.882302 -265.312398)
		(end 47.753778 -265.440922)
		(width 0.20066)
		(layer "F.Cu")
		(net "M_B_CPU1_SA_CA<1>")
	)
	(segment
		(start 44.112942 -265.316716)
		(end 42.415714 -265.316716)
		(width 0.20066)
		(layer "F.Cu")
		(net "M_B_CPU1_SA_CA<1>")
	)
	(segment
		(start 47.060358 -265.741658)
		(end 44.987464 -265.741658)
		(width 0.1016)
		(layer "F.Cu")
		(net "M_B_CPU1_SA_CA<1>")
	)
	(segment
		(start 44.735242 -265.755882)
		(end 44.38142 -265.755882)
		(width 0.20066)
		(layer "F.Cu")
		(net "M_B_CPU1_SA_CA<1>")
	)
	(segment
		(start 44.238926 -265.4427)
		(end 44.112942 -265.316716)
		(width 0.20066)
		(layer "F.Cu")
		(net "M_B_CPU1_SA_CA<1>")
	)
	(segment
		(start 47.60468 -265.741658)
		(end 47.060358 -265.741658)
		(width 0.20066)
		(layer "F.Cu")
		(net "M_B_CPU1_SA_CA<1>")
	)
	(segment
		(start 49.959514 -265.316716)
		(end 49.143412 -265.316716)
		(width 0.20066)
		(layer "F.Cu")
		(net "M_B_CPU1_SA_CA<1>")
	)
	(segment
		(start 44.238926 -265.613388)
		(end 44.238926 -265.4427)
		(width 0.20066)
		(layer "F.Cu")
		(net "M_B_CPU1_SA_CA<1>")
	)
	(segment
		(start 44.987464 -265.741658)
		(end 44.749466 -265.741658)
		(width 0.101854)
		(layer "F.Cu")
		(net "M_B_CPU1_SA_CA<1>")
	)
	(segment
		(start 91.074494 -255.547368)
		(end 91.074748 -255.547622)
		(width 0.20066)
		(layer "F.Cu")
		(net "M_B_CPU1_SA_CA<1>")
	)
	(segment
		(start 51.089814 -265.316716)
		(end 49.959514 -265.316716)
		(width 0.20066)
		(layer "F.Cu")
		(net "M_B_CPU1_SA_CA<1>")
	)
	(segment
		(start 47.753778 -265.440922)
		(end 47.753778 -265.59256)
		(width 0.20066)
		(layer "F.Cu")
		(net "M_B_CPU1_SA_CA<1>")
	)
	(segment
		(start 61.72454 -262.386572)
		(end 61.17209 -262.386572)
		(width 0.18288)
		(layer "In2.Cu")
		(net "M_B_CPU1_SA_CA<1>")
	)
	(segment
		(start 84.120228 -255.272032)
		(end 83.876134 -255.272032)
		(width 0.088646)
		(layer "In2.Cu")
		(net "M_B_CPU1_SA_CA<1>")
	)
	(segment
		(start 51.247802 -264.86612)
		(end 51.089814 -265.024108)
		(width 0.18288)
		(layer "In2.Cu")
		(net "M_B_CPU1_SA_CA<1>")
	)
	(segment
		(start 54.370986 -264.850372)
		(end 53.978302 -265.243056)
		(width 0.18288)
		(layer "In2.Cu")
		(net "M_B_CPU1_SA_CA<1>")
	)
	(segment
		(start 84.495894 -255.172464)
		(end 84.219796 -255.172464)
		(width 0.088646)
		(layer "In2.Cu")
		(net "M_B_CPU1_SA_CA<1>")
	)
	(segment
		(start 84.219796 -255.172464)
		(end 84.120228 -255.272032)
		(width 0.088646)
		(layer "In2.Cu")
		(net "M_B_CPU1_SA_CA<1>")
	)
	(segment
		(start 56.519826 -263.255252)
		(end 56.208422 -263.255252)
		(width 0.18288)
		(layer "In2.Cu")
		(net "M_B_CPU1_SA_CA<1>")
	)
	(segment
		(start 57.985914 -262.825738)
		(end 56.94934 -262.825738)
		(width 0.18288)
		(layer "In2.Cu")
		(net "M_B_CPU1_SA_CA<1>")
	)
	(segment
		(start 60.46851 -262.019542)
		(end 60.10148 -262.386572)
		(width 0.18288)
		(layer "In2.Cu")
		(net "M_B_CPU1_SA_CA<1>")
	)
	(segment
		(start 89.39276 -255.22936)
		(end 89.382346 -255.223264)
		(width 0.088646)
		(layer "In2.Cu")
		(net "M_B_CPU1_SA_CA<1>")
	)
	(segment
		(start 61.17209 -262.386572)
		(end 60.80506 -262.019542)
		(width 0.18288)
		(layer "In2.Cu")
		(net "M_B_CPU1_SA_CA<1>")
	)
	(segment
		(start 52.365148 -264.600944)
		(end 51.753516 -264.600944)
		(width 0.18288)
		(layer "In2.Cu")
		(net "M_B_CPU1_SA_CA<1>")
	)
	(segment
		(start 52.61991 -265.036046)
		(end 52.61991 -264.855706)
		(width 0.18288)
		(layer "In2.Cu")
		(net "M_B_CPU1_SA_CA<1>")
	)
	(segment
		(start 74.153268 -257.9243)
		(end 66.648838 -261.02564)
		(width 0.18288)
		(layer "In2.Cu")
		(net "M_B_CPU1_SA_CA<1>")
	)
	(segment
		(start 52.61991 -264.855706)
		(end 52.365148 -264.600944)
		(width 0.18288)
		(layer "In2.Cu")
		(net "M_B_CPU1_SA_CA<1>")
	)
	(segment
		(start 91.074748 -255.547622)
		(end 90.351102 -255.240028)
		(width 0.088646)
		(layer "In2.Cu")
		(net "M_B_CPU1_SA_CA<1>")
	)
	(segment
		(start 65.651126 -261.52221)
		(end 65.27038 -261.141464)
		(width 0.18288)
		(layer "In2.Cu")
		(net "M_B_CPU1_SA_CA<1>")
	)
	(segment
		(start 52.82692 -265.243056)
		(end 52.61991 -265.036046)
		(width 0.18288)
		(layer "In2.Cu")
		(net "M_B_CPU1_SA_CA<1>")
	)
	(segment
		(start 64.947546 -261.141464)
		(end 64.5668 -261.52221)
		(width 0.18288)
		(layer "In2.Cu")
		(net "M_B_CPU1_SA_CA<1>")
	)
	(segment
		(start 62.758066 -261.846314)
		(end 62.99708 -262.08482)
		(width 0.18288)
		(layer "In2.Cu")
		(net "M_B_CPU1_SA_CA<1>")
	)
	(segment
		(start 62.997334 -262.357362)
		(end 62.736222 -262.618982)
		(width 0.18288)
		(layer "In2.Cu")
		(net "M_B_CPU1_SA_CA<1>")
	)
	(segment
		(start 54.885336 -264.850372)
		(end 54.370986 -264.850372)
		(width 0.18288)
		(layer "In2.Cu")
		(net "M_B_CPU1_SA_CA<1>")
	)
	(segment
		(start 64.5668 -261.52221)
		(end 63.656972 -261.52221)
		(width 0.18288)
		(layer "In2.Cu")
		(net "M_B_CPU1_SA_CA<1>")
	)
	(segment
		(start 60.80506 -262.019542)
		(end 60.46851 -262.019542)
		(width 0.18288)
		(layer "In2.Cu")
		(net "M_B_CPU1_SA_CA<1>")
	)
	(segment
		(start 74.453242 -257.624326)
		(end 74.153268 -257.9243)
		(width 0.18288)
		(layer "In2.Cu")
		(net "M_B_CPU1_SA_CA<1>")
	)
	(segment
		(start 55.393336 -264.070338)
		(end 55.393844 -264.222992)
		(width 0.18288)
		(layer "In2.Cu")
		(net "M_B_CPU1_SA_CA<1>")
	)
	(segment
		(start 65.27038 -261.141464)
		(end 64.947546 -261.141464)
		(width 0.18288)
		(layer "In2.Cu")
		(net "M_B_CPU1_SA_CA<1>")
	)
	(segment
		(start 51.753516 -264.600944)
		(end 51.48834 -264.86612)
		(width 0.18288)
		(layer "In2.Cu")
		(net "M_B_CPU1_SA_CA<1>")
	)
	(segment
		(start 83.876134 -255.272032)
		(end 82.711544 -255.272032)
		(width 0.18288)
		(layer "In2.Cu")
		(net "M_B_CPU1_SA_CA<1>")
	)
	(segment
		(start 51.089814 -265.024108)
		(end 51.089814 -265.316716)
		(width 0.18288)
		(layer "In2.Cu")
		(net "M_B_CPU1_SA_CA<1>")
	)
	(segment
		(start 61.95695 -262.618982)
		(end 61.72454 -262.386572)
		(width 0.18288)
		(layer "In2.Cu")
		(net "M_B_CPU1_SA_CA<1>")
	)
	(segment
		(start 62.757812 -261.573772)
		(end 62.758066 -261.846314)
		(width 0.18288)
		(layer "In2.Cu")
		(net "M_B_CPU1_SA_CA<1>")
	)
	(segment
		(start 88.452706 -255.22936)
		(end 88.442292 -255.223264)
		(width 0.088646)
		(layer "In2.Cu")
		(net "M_B_CPU1_SA_CA<1>")
	)
	(segment
		(start 51.48834 -264.86612)
		(end 51.247802 -264.86612)
		(width 0.18288)
		(layer "In2.Cu")
		(net "M_B_CPU1_SA_CA<1>")
	)
	(segment
		(start 66.648838 -261.02564)
		(end 66.482214 -261.4295)
		(width 0.18288)
		(layer "In2.Cu")
		(net "M_B_CPU1_SA_CA<1>")
	)
	(segment
		(start 62.99708 -262.08482)
		(end 62.997334 -262.357362)
		(width 0.18288)
		(layer "In2.Cu")
		(net "M_B_CPU1_SA_CA<1>")
	)
	(segment
		(start 58.494168 -263.333992)
		(end 57.985914 -262.825738)
		(width 0.18288)
		(layer "In2.Cu")
		(net "M_B_CPU1_SA_CA<1>")
	)
	(segment
		(start 55.393844 -264.341864)
		(end 54.885336 -264.850372)
		(width 0.18288)
		(layer "In2.Cu")
		(net "M_B_CPU1_SA_CA<1>")
	)
	(segment
		(start 90.351102 -255.240028)
		(end 90.321892 -255.223264)
		(width 0.088646)
		(layer "In2.Cu")
		(net "M_B_CPU1_SA_CA<1>")
	)
	(segment
		(start 55.393844 -264.222992)
		(end 55.393844 -264.341864)
		(width 0.18288)
		(layer "In2.Cu")
		(net "M_B_CPU1_SA_CA<1>")
	)
	(segment
		(start 63.095632 -261.234936)
		(end 62.757812 -261.573772)
		(width 0.18288)
		(layer "In2.Cu")
		(net "M_B_CPU1_SA_CA<1>")
	)
	(segment
		(start 63.656972 -261.52221)
		(end 63.368936 -261.234682)
		(width 0.18288)
		(layer "In2.Cu")
		(net "M_B_CPU1_SA_CA<1>")
	)
	(segment
		(start 66.482214 -261.4295)
		(end 66.257932 -261.52221)
		(width 0.18288)
		(layer "In2.Cu")
		(net "M_B_CPU1_SA_CA<1>")
	)
	(segment
		(start 80.35925 -257.624326)
		(end 74.453242 -257.624326)
		(width 0.18288)
		(layer "In2.Cu")
		(net "M_B_CPU1_SA_CA<1>")
	)
	(segment
		(start 59.714638 -262.386572)
		(end 58.767218 -263.333992)
		(width 0.18288)
		(layer "In2.Cu")
		(net "M_B_CPU1_SA_CA<1>")
	)
	(segment
		(start 82.711544 -255.272032)
		(end 80.35925 -257.624326)
		(width 0.18288)
		(layer "In2.Cu")
		(net "M_B_CPU1_SA_CA<1>")
	)
	(segment
		(start 56.94934 -262.825738)
		(end 56.519826 -263.255252)
		(width 0.18288)
		(layer "In2.Cu")
		(net "M_B_CPU1_SA_CA<1>")
	)
	(segment
		(start 66.257932 -261.52221)
		(end 65.651126 -261.52221)
		(width 0.18288)
		(layer "In2.Cu")
		(net "M_B_CPU1_SA_CA<1>")
	)
	(segment
		(start 56.208422 -263.255252)
		(end 55.393336 -264.070338)
		(width 0.18288)
		(layer "In2.Cu")
		(net "M_B_CPU1_SA_CA<1>")
	)
	(segment
		(start 53.978302 -265.243056)
		(end 52.82692 -265.243056)
		(width 0.18288)
		(layer "In2.Cu")
		(net "M_B_CPU1_SA_CA<1>")
	)
	(segment
		(start 63.368936 -261.234682)
		(end 63.095632 -261.234936)
		(width 0.18288)
		(layer "In2.Cu")
		(net "M_B_CPU1_SA_CA<1>")
	)
	(segment
		(start 62.736222 -262.618982)
		(end 61.95695 -262.618982)
		(width 0.18288)
		(layer "In2.Cu")
		(net "M_B_CPU1_SA_CA<1>")
	)
	(segment
		(start 58.767218 -263.333992)
		(end 58.494168 -263.333992)
		(width 0.18288)
		(layer "In2.Cu")
		(net "M_B_CPU1_SA_CA<1>")
	)
	(segment
		(start 60.10148 -262.386572)
		(end 59.714638 -262.386572)
		(width 0.18288)
		(layer "In2.Cu")
		(net "M_B_CPU1_SA_CA<1>")
	)
	(arc
		(start 89.382346 -255.223264)
		(mid 89.195148 -255.173121)
		(end 89.00795 -255.223264)
		(width 0.088646)
		(layer "In2.Cu")
		(net "M_B_CPU1_SA_CA<1>")
	)
	(arc
		(start 90.321892 -255.223264)
		(mid 90.134694 -255.173121)
		(end 89.947496 -255.223264)
		(width 0.088646)
		(layer "In2.Cu")
		(net "M_B_CPU1_SA_CA<1>")
	)
	(arc
		(start 89.947496 -255.223264)
		(mid 89.670937 -255.298973)
		(end 89.39276 -255.22936)
		(width 0.088646)
		(layer "In2.Cu")
		(net "M_B_CPU1_SA_CA<1>")
	)
	(arc
		(start 87.502492 -255.223264)
		(mid 87.315294 -255.173121)
		(end 87.128096 -255.223264)
		(width 0.088646)
		(layer "In2.Cu")
		(net "M_B_CPU1_SA_CA<1>")
	)
	(arc
		(start 86.562692 -255.223264)
		(mid 86.375494 -255.173121)
		(end 86.188296 -255.223264)
		(width 0.088646)
		(layer "In2.Cu")
		(net "M_B_CPU1_SA_CA<1>")
	)
	(arc
		(start 87.128096 -255.223264)
		(mid 86.845394 -255.299006)
		(end 86.562692 -255.223264)
		(width 0.088646)
		(layer "In2.Cu")
		(net "M_B_CPU1_SA_CA<1>")
	)
	(arc
		(start 88.067896 -255.223264)
		(mid 87.785194 -255.299006)
		(end 87.502492 -255.223264)
		(width 0.088646)
		(layer "In2.Cu")
		(net "M_B_CPU1_SA_CA<1>")
	)
	(arc
		(start 85.622892 -255.223264)
		(mid 85.435694 -255.173121)
		(end 85.248496 -255.223264)
		(width 0.088646)
		(layer "In2.Cu")
		(net "M_B_CPU1_SA_CA<1>")
	)
	(arc
		(start 84.683092 -255.223264)
		(mid 84.592836 -255.185542)
		(end 84.495894 -255.172464)
		(width 0.088646)
		(layer "In2.Cu")
		(net "M_B_CPU1_SA_CA<1>")
	)
	(arc
		(start 88.442292 -255.223264)
		(mid 88.255094 -255.173121)
		(end 88.067896 -255.223264)
		(width 0.088646)
		(layer "In2.Cu")
		(net "M_B_CPU1_SA_CA<1>")
	)
	(arc
		(start 89.00795 -255.223264)
		(mid 88.731137 -255.2991)
		(end 88.452706 -255.22936)
		(width 0.088646)
		(layer "In2.Cu")
		(net "M_B_CPU1_SA_CA<1>")
	)
	(arc
		(start 85.248496 -255.223264)
		(mid 84.965794 -255.299006)
		(end 84.683092 -255.223264)
		(width 0.088646)
		(layer "In2.Cu")
		(net "M_B_CPU1_SA_CA<1>")
	)
	(arc
		(start 86.188296 -255.223264)
		(mid 85.905594 -255.299006)
		(end 85.622892 -255.223264)
		(width 0.088646)
		(layer "In2.Cu")
		(net "M_B_CPU1_SA_CA<1>")
	)
	(segment
		(start 43.285918 -265.741658)
		(end 41.3004 -265.741658)
		(width 0.1016)
		(layer "F.Cu")
		(net "M_B_CPU1_SA_CA<0>")
	)
	(segment
		(start 46.964346 -266.1666)
		(end 45.859446 -266.1666)
		(width 0.20066)
		(layer "F.Cu")
		(net "M_B_CPU1_SA_CA<0>")
	)
	(segment
		(start 41.3004 -265.741658)
		(end 41.29151 -265.732768)
		(width 0.1016)
		(layer "F.Cu")
		(net "M_B_CPU1_SA_CA<0>")
	)
	(segment
		(start 44.22013 -266.1666)
		(end 43.795188 -265.741658)
		(width 0.20066)
		(layer "F.Cu")
		(net "M_B_CPU1_SA_CA<0>")
	)
	(segment
		(start 40.36568 -266.377928)
		(end 39.861236 -266.377928)
		(width 0.20066)
		(layer "F.Cu")
		(net "M_B_CPU1_SA_CA<0>")
	)
	(segment
		(start 40.682672 -265.732768)
		(end 40.520112 -265.895328)
		(width 0.20066)
		(layer "F.Cu")
		(net "M_B_CPU1_SA_CA<0>")
	)
	(segment
		(start 39.649908 -266.1666)
		(end 38.315646 -266.1666)
		(width 0.20066)
		(layer "F.Cu")
		(net "M_B_CPU1_SA_CA<0>")
	)
	(segment
		(start 88.255094 -255.011682)
		(end 88.255094 -255.547622)
		(width 0.20066)
		(layer "F.Cu")
		(net "M_B_CPU1_SA_CA<0>")
	)
	(segment
		(start 40.520112 -266.223496)
		(end 40.36568 -266.377928)
		(width 0.20066)
		(layer "F.Cu")
		(net "M_B_CPU1_SA_CA<0>")
	)
	(segment
		(start 41.29151 -265.732768)
		(end 40.682672 -265.732768)
		(width 0.20066)
		(layer "F.Cu")
		(net "M_B_CPU1_SA_CA<0>")
	)
	(segment
		(start 40.520112 -265.895328)
		(end 40.520112 -266.223496)
		(width 0.20066)
		(layer "F.Cu")
		(net "M_B_CPU1_SA_CA<0>")
	)
	(segment
		(start 39.861236 -266.377928)
		(end 39.649908 -266.1666)
		(width 0.20066)
		(layer "F.Cu")
		(net "M_B_CPU1_SA_CA<0>")
	)
	(segment
		(start 43.795188 -265.741658)
		(end 43.616626 -265.741658)
		(width 0.20066)
		(layer "F.Cu")
		(net "M_B_CPU1_SA_CA<0>")
	)
	(segment
		(start 45.859446 -266.1666)
		(end 44.22013 -266.1666)
		(width 0.20066)
		(layer "F.Cu")
		(net "M_B_CPU1_SA_CA<0>")
	)
	(segment
		(start 43.616626 -265.741658)
		(end 43.285918 -265.741658)
		(width 0.101854)
		(layer "F.Cu")
		(net "M_B_CPU1_SA_CA<0>")
	)
	(segment
		(start 48.334168 -265.285982)
		(end 48.334168 -264.78865)
		(width 0.18288)
		(layer "In2.Cu")
		(net "M_B_CPU1_SA_CA<0>")
	)
	(segment
		(start 55.95366 -264.503154)
		(end 54.696614 -265.7602)
		(width 0.18288)
		(layer "In2.Cu")
		(net "M_B_CPU1_SA_CA<0>")
	)
	(segment
		(start 48.494188 -265.446002)
		(end 48.334168 -265.285982)
		(width 0.18288)
		(layer "In2.Cu")
		(net "M_B_CPU1_SA_CA<0>")
	)
	(segment
		(start 82.75828 -255.713992)
		(end 80.502506 -257.969766)
		(width 0.18288)
		(layer "In2.Cu")
		(net "M_B_CPU1_SA_CA<0>")
	)
	(segment
		(start 51.506628 -265.598656)
		(end 51.363626 -265.741658)
		(width 0.18288)
		(layer "In2.Cu")
		(net "M_B_CPU1_SA_CA<0>")
	)
	(segment
		(start 65.846452 -262.295132)
		(end 63.810388 -262.295132)
		(width 0.18288)
		(layer "In2.Cu")
		(net "M_B_CPU1_SA_CA<0>")
	)
	(segment
		(start 66.276728 -262.082788)
		(end 66.058796 -262.082788)
		(width 0.18288)
		(layer "In2.Cu")
		(net "M_B_CPU1_SA_CA<0>")
	)
	(segment
		(start 74.134726 -258.48183)
		(end 67.035426 -261.422388)
		(width 0.18288)
		(layer "In2.Cu")
		(net "M_B_CPU1_SA_CA<0>")
	)
	(segment
		(start 47.45609 -265.24712)
		(end 47.22241 -265.811508)
		(width 0.18288)
		(layer "In2.Cu")
		(net "M_B_CPU1_SA_CA<0>")
	)
	(segment
		(start 66.862198 -261.840218)
		(end 66.276728 -262.082788)
		(width 0.18288)
		(layer "In2.Cu")
		(net "M_B_CPU1_SA_CA<0>")
	)
	(segment
		(start 63.024512 -263.081008)
		(end 62.858904 -263.149588)
		(width 0.18288)
		(layer "In2.Cu")
		(net "M_B_CPU1_SA_CA<0>")
	)
	(segment
		(start 56.237886 -264.001504)
		(end 55.95366 -264.28573)
		(width 0.18288)
		(layer "In2.Cu")
		(net "M_B_CPU1_SA_CA<0>")
	)
	(segment
		(start 48.14951 -264.603992)
		(end 47.64913 -264.603992)
		(width 0.18288)
		(layer "In2.Cu")
		(net "M_B_CPU1_SA_CA<0>")
	)
	(segment
		(start 63.810388 -262.295132)
		(end 63.024512 -263.081008)
		(width 0.18288)
		(layer "In2.Cu")
		(net "M_B_CPU1_SA_CA<0>")
	)
	(segment
		(start 48.334168 -264.78865)
		(end 48.14951 -264.603992)
		(width 0.18288)
		(layer "In2.Cu")
		(net "M_B_CPU1_SA_CA<0>")
	)
	(segment
		(start 62.858904 -263.149588)
		(end 59.681618 -263.149588)
		(width 0.18288)
		(layer "In2.Cu")
		(net "M_B_CPU1_SA_CA<0>")
	)
	(segment
		(start 74.64679 -257.969766)
		(end 74.134726 -258.48183)
		(width 0.18288)
		(layer "In2.Cu")
		(net "M_B_CPU1_SA_CA<0>")
	)
	(segment
		(start 47.153576 -265.97737)
		(end 46.964346 -266.1666)
		(width 0.18288)
		(layer "In2.Cu")
		(net "M_B_CPU1_SA_CA<0>")
	)
	(segment
		(start 52.149248 -265.7602)
		(end 51.759104 -265.598656)
		(width 0.18288)
		(layer "In2.Cu")
		(net "M_B_CPU1_SA_CA<0>")
	)
	(segment
		(start 84.495894 -255.922526)
		(end 84.281772 -255.922526)
		(width 0.088646)
		(layer "In2.Cu")
		(net "M_B_CPU1_SA_CA<0>")
	)
	(segment
		(start 59.681618 -263.149588)
		(end 58.829702 -264.001504)
		(width 0.18288)
		(layer "In2.Cu")
		(net "M_B_CPU1_SA_CA<0>")
	)
	(segment
		(start 51.363626 -265.741658)
		(end 49.146968 -265.741658)
		(width 0.18288)
		(layer "In2.Cu")
		(net "M_B_CPU1_SA_CA<0>")
	)
	(segment
		(start 88.411558 -255.81864)
		(end 88.390476 -255.896618)
		(width 0.088646)
		(layer "In2.Cu")
		(net "M_B_CPU1_SA_CA<0>")
	)
	(segment
		(start 54.696614 -265.7602)
		(end 52.149248 -265.7602)
		(width 0.18288)
		(layer "In2.Cu")
		(net "M_B_CPU1_SA_CA<0>")
	)
	(segment
		(start 84.281772 -255.922526)
		(end 84.073238 -255.713992)
		(width 0.088646)
		(layer "In2.Cu")
		(net "M_B_CPU1_SA_CA<0>")
	)
	(segment
		(start 58.829702 -264.001504)
		(end 56.237886 -264.001504)
		(width 0.18288)
		(layer "In2.Cu")
		(net "M_B_CPU1_SA_CA<0>")
	)
	(segment
		(start 55.95366 -264.28573)
		(end 55.95366 -264.503154)
		(width 0.18288)
		(layer "In2.Cu")
		(net "M_B_CPU1_SA_CA<0>")
	)
	(segment
		(start 83.876134 -255.713992)
		(end 82.75828 -255.713992)
		(width 0.18288)
		(layer "In2.Cu")
		(net "M_B_CPU1_SA_CA<0>")
	)
	(segment
		(start 47.45609 -264.797032)
		(end 47.45609 -265.24712)
		(width 0.18288)
		(layer "In2.Cu")
		(net "M_B_CPU1_SA_CA<0>")
	)
	(segment
		(start 49.146968 -265.741658)
		(end 48.851312 -265.446002)
		(width 0.18288)
		(layer "In2.Cu")
		(net "M_B_CPU1_SA_CA<0>")
	)
	(segment
		(start 47.64913 -264.603992)
		(end 47.45609 -264.797032)
		(width 0.18288)
		(layer "In2.Cu")
		(net "M_B_CPU1_SA_CA<0>")
	)
	(segment
		(start 84.073238 -255.713992)
		(end 83.876134 -255.713992)
		(width 0.088646)
		(layer "In2.Cu")
		(net "M_B_CPU1_SA_CA<0>")
	)
	(segment
		(start 48.851312 -265.446002)
		(end 48.494188 -265.446002)
		(width 0.18288)
		(layer "In2.Cu")
		(net "M_B_CPU1_SA_CA<0>")
	)
	(segment
		(start 66.058796 -262.082788)
		(end 65.846452 -262.295132)
		(width 0.18288)
		(layer "In2.Cu")
		(net "M_B_CPU1_SA_CA<0>")
	)
	(segment
		(start 80.502506 -257.969766)
		(end 74.64679 -257.969766)
		(width 0.18288)
		(layer "In2.Cu")
		(net "M_B_CPU1_SA_CA<0>")
	)
	(segment
		(start 88.255094 -255.547622)
		(end 88.411558 -255.81864)
		(width 0.088646)
		(layer "In2.Cu")
		(net "M_B_CPU1_SA_CA<0>")
	)
	(segment
		(start 47.22241 -265.811508)
		(end 47.153576 -265.97737)
		(width 0.18288)
		(layer "In2.Cu")
		(net "M_B_CPU1_SA_CA<0>")
	)
	(segment
		(start 51.759104 -265.598656)
		(end 51.506628 -265.598656)
		(width 0.18288)
		(layer "In2.Cu")
		(net "M_B_CPU1_SA_CA<0>")
	)
	(segment
		(start 67.035426 -261.422388)
		(end 66.862198 -261.840218)
		(width 0.18288)
		(layer "In2.Cu")
		(net "M_B_CPU1_SA_CA<0>")
	)
	(arc
		(start 84.683092 -255.87198)
		(mid 84.59282 -255.909579)
		(end 84.495894 -255.922526)
		(width 0.088646)
		(layer "In2.Cu")
		(net "M_B_CPU1_SA_CA<0>")
	)
	(arc
		(start 87.128096 -255.87198)
		(mid 86.845394 -255.796204)
		(end 86.562692 -255.87198)
		(width 0.088646)
		(layer "In2.Cu")
		(net "M_B_CPU1_SA_CA<0>")
	)
	(arc
		(start 86.188296 -255.87198)
		(mid 85.905594 -255.796204)
		(end 85.622892 -255.87198)
		(width 0.088646)
		(layer "In2.Cu")
		(net "M_B_CPU1_SA_CA<0>")
	)
	(arc
		(start 85.248496 -255.87198)
		(mid 84.965794 -255.796204)
		(end 84.683092 -255.87198)
		(width 0.088646)
		(layer "In2.Cu")
		(net "M_B_CPU1_SA_CA<0>")
	)
	(arc
		(start 87.502492 -255.87198)
		(mid 87.315294 -255.922123)
		(end 87.128096 -255.87198)
		(width 0.088646)
		(layer "In2.Cu")
		(net "M_B_CPU1_SA_CA<0>")
	)
	(arc
		(start 86.562692 -255.87198)
		(mid 86.375494 -255.922123)
		(end 86.188296 -255.87198)
		(width 0.088646)
		(layer "In2.Cu")
		(net "M_B_CPU1_SA_CA<0>")
	)
	(arc
		(start 88.390476 -255.896618)
		(mid 88.22638 -255.920965)
		(end 88.067896 -255.87198)
		(width 0.088646)
		(layer "In2.Cu")
		(net "M_B_CPU1_SA_CA<0>")
	)
	(arc
		(start 85.622892 -255.87198)
		(mid 85.435694 -255.922123)
		(end 85.248496 -255.87198)
		(width 0.088646)
		(layer "In2.Cu")
		(net "M_B_CPU1_SA_CA<0>")
	)
	(arc
		(start 88.067896 -255.87198)
		(mid 87.785194 -255.796204)
		(end 87.502492 -255.87198)
		(width 0.088646)
		(layer "In2.Cu")
		(net "M_B_CPU1_SA_CA<0>")
	)
	(segment
		(start 49.959514 -260.21665)
		(end 51.089814 -260.21665)
		(width 0.20066)
		(layer "F.Cu")
		(net "M_B_CPU1_CLK_DP<1>")
	)
	(segment
		(start 94.253812 -250.15571)
		(end 94.253812 -249.620024)
		(width 0.20066)
		(layer "F.Cu")
		(net "M_B_CPU1_CLK_DP<1>")
	)
	(segment
		(start 94.254066 -250.155964)
		(end 94.253812 -250.15571)
		(width 0.20066)
		(layer "F.Cu")
		(net "M_B_CPU1_CLK_DP<1>")
	)
	(segment
		(start 51.490626 -259.680202)
		(end 51.089814 -260.081014)
		(width 0.18288)
		(layer "In2.Cu")
		(net "M_B_CPU1_CLK_DP<1>")
	)
	(segment
		(start 93.941392 -250.46559)
		(end 93.65234 -250.754896)
		(width 0.18288)
		(layer "In2.Cu")
		(net "M_B_CPU1_CLK_DP<1>")
	)
	(segment
		(start 59.19216 -256.534666)
		(end 52.504086 -257.970528)
		(width 0.18288)
		(layer "In2.Cu")
		(net "M_B_CPU1_CLK_DP<1>")
	)
	(segment
		(start 51.843432 -259.166106)
		(end 51.732434 -259.434838)
		(width 0.18288)
		(layer "In2.Cu")
		(net "M_B_CPU1_CLK_DP<1>")
	)
	(segment
		(start 51.843432 -258.378198)
		(end 51.843432 -259.166106)
		(width 0.18288)
		(layer "In2.Cu")
		(net "M_B_CPU1_CLK_DP<1>")
	)
	(segment
		(start 51.490626 -259.676646)
		(end 51.490626 -259.680202)
		(width 0.18288)
		(layer "In2.Cu")
		(net "M_B_CPU1_CLK_DP<1>")
	)
	(segment
		(start 86.362286 -251.857002)
		(end 82.703416 -251.857002)
		(width 0.18288)
		(layer "In2.Cu")
		(net "M_B_CPU1_CLK_DP<1>")
	)
	(segment
		(start 51.732434 -259.434838)
		(end 51.490626 -259.676646)
		(width 0.18288)
		(layer "In2.Cu")
		(net "M_B_CPU1_CLK_DP<1>")
	)
	(segment
		(start 51.089814 -260.081014)
		(end 51.089814 -260.21665)
		(width 0.18288)
		(layer "In2.Cu")
		(net "M_B_CPU1_CLK_DP<1>")
	)
	(segment
		(start 64.730376 -256.534666)
		(end 59.19216 -256.534666)
		(width 0.18288)
		(layer "In2.Cu")
		(net "M_B_CPU1_CLK_DP<1>")
	)
	(segment
		(start 71.410322 -255.206246)
		(end 71.035164 -255.280922)
		(width 0.18288)
		(layer "In2.Cu")
		(net "M_B_CPU1_CLK_DP<1>")
	)
	(segment
		(start 93.65234 -250.754896)
		(end 91.687396 -251.568712)
		(width 0.18288)
		(layer "In2.Cu")
		(net "M_B_CPU1_CLK_DP<1>")
	)
	(segment
		(start 87.058754 -251.568712)
		(end 86.362286 -251.857002)
		(width 0.18288)
		(layer "In2.Cu")
		(net "M_B_CPU1_CLK_DP<1>")
	)
	(segment
		(start 71.035164 -255.280922)
		(end 64.730376 -256.534666)
		(width 0.18288)
		(layer "In2.Cu")
		(net "M_B_CPU1_CLK_DP<1>")
	)
	(segment
		(start 91.687396 -251.568712)
		(end 87.058754 -251.568712)
		(width 0.18288)
		(layer "In2.Cu")
		(net "M_B_CPU1_CLK_DP<1>")
	)
	(segment
		(start 82.703416 -251.857002)
		(end 79.354172 -255.206246)
		(width 0.18288)
		(layer "In2.Cu")
		(net "M_B_CPU1_CLK_DP<1>")
	)
	(segment
		(start 93.941392 -249.932444)
		(end 93.941392 -250.46559)
		(width 0.18288)
		(layer "In2.Cu")
		(net "M_B_CPU1_CLK_DP<1>")
	)
	(segment
		(start 94.253812 -249.620024)
		(end 93.941392 -249.932444)
		(width 0.18288)
		(layer "In2.Cu")
		(net "M_B_CPU1_CLK_DP<1>")
	)
	(segment
		(start 52.504086 -257.970528)
		(end 52.01666 -258.13639)
		(width 0.18288)
		(layer "In2.Cu")
		(net "M_B_CPU1_CLK_DP<1>")
	)
	(segment
		(start 79.354172 -255.206246)
		(end 71.410322 -255.206246)
		(width 0.18288)
		(layer "In2.Cu")
		(net "M_B_CPU1_CLK_DP<1>")
	)
	(segment
		(start 52.01666 -258.13639)
		(end 51.843432 -258.378198)
		(width 0.18288)
		(layer "In2.Cu")
		(net "M_B_CPU1_CLK_DP<1>")
	)
	(segment
		(start 42.415714 -260.21665)
		(end 43.520614 -260.21665)
		(width 0.20066)
		(layer "F.Cu")
		(net "M_B_CPU1_CLK_DP<0>")
	)
	(segment
		(start 92.374466 -250.155964)
		(end 92.374466 -249.620278)
		(width 0.20066)
		(layer "F.Cu")
		(net "M_B_CPU1_CLK_DP<0>")
	)
	(segment
		(start 92.374466 -249.620278)
		(end 92.374212 -249.620024)
		(width 0.20066)
		(layer "F.Cu")
		(net "M_B_CPU1_CLK_DP<0>")
	)
	(segment
		(start 92.374212 -249.620024)
		(end 92.047822 -249.946414)
		(width 0.18288)
		(layer "In2.Cu")
		(net "M_B_CPU1_CLK_DP<0>")
	)
	(segment
		(start 87.250524 -250.684792)
		(end 86.062058 -251.177044)
		(width 0.18288)
		(layer "In2.Cu")
		(net "M_B_CPU1_CLK_DP<0>")
	)
	(segment
		(start 91.471496 -250.684792)
		(end 87.250524 -250.684792)
		(width 0.18288)
		(layer "In2.Cu")
		(net "M_B_CPU1_CLK_DP<0>")
	)
	(segment
		(start 44.20489 -259.965698)
		(end 43.771566 -259.965698)
		(width 0.18288)
		(layer "In2.Cu")
		(net "M_B_CPU1_CLK_DP<0>")
	)
	(segment
		(start 44.585128 -259.58546)
		(end 44.20489 -259.965698)
		(width 0.18288)
		(layer "In2.Cu")
		(net "M_B_CPU1_CLK_DP<0>")
	)
	(segment
		(start 43.771566 -259.965698)
		(end 43.520614 -260.21665)
		(width 0.18288)
		(layer "In2.Cu")
		(net "M_B_CPU1_CLK_DP<0>")
	)
	(segment
		(start 58.247534 -255.696466)
		(end 48.92802 -257.612642)
		(width 0.18288)
		(layer "In2.Cu")
		(net "M_B_CPU1_CLK_DP<0>")
	)
	(segment
		(start 44.585128 -258.981448)
		(end 44.585128 -259.58546)
		(width 0.18288)
		(layer "In2.Cu")
		(net "M_B_CPU1_CLK_DP<0>")
	)
	(segment
		(start 44.313856 -258.710176)
		(end 44.585128 -258.981448)
		(width 0.18288)
		(layer "In2.Cu")
		(net "M_B_CPU1_CLK_DP<0>")
	)
	(segment
		(start 48.92802 -257.612642)
		(end 44.883324 -257.612642)
		(width 0.18288)
		(layer "In2.Cu")
		(net "M_B_CPU1_CLK_DP<0>")
	)
	(segment
		(start 44.313856 -258.18211)
		(end 44.313856 -258.710176)
		(width 0.18288)
		(layer "In2.Cu")
		(net "M_B_CPU1_CLK_DP<0>")
	)
	(segment
		(start 63.45047 -255.696466)
		(end 58.247534 -255.696466)
		(width 0.18288)
		(layer "In2.Cu")
		(net "M_B_CPU1_CLK_DP<0>")
	)
	(segment
		(start 44.883324 -257.612642)
		(end 44.313856 -258.18211)
		(width 0.18288)
		(layer "In2.Cu")
		(net "M_B_CPU1_CLK_DP<0>")
	)
	(segment
		(start 92.047822 -249.946414)
		(end 92.047822 -250.306586)
		(width 0.18288)
		(layer "In2.Cu")
		(net "M_B_CPU1_CLK_DP<0>")
	)
	(segment
		(start 69.149468 -254.540512)
		(end 63.45047 -255.696466)
		(width 0.18288)
		(layer "In2.Cu")
		(net "M_B_CPU1_CLK_DP<0>")
	)
	(segment
		(start 79.078074 -254.540512)
		(end 69.149468 -254.540512)
		(width 0.18288)
		(layer "In2.Cu")
		(net "M_B_CPU1_CLK_DP<0>")
	)
	(segment
		(start 91.80957 -250.544838)
		(end 91.471496 -250.684792)
		(width 0.18288)
		(layer "In2.Cu")
		(net "M_B_CPU1_CLK_DP<0>")
	)
	(segment
		(start 92.047822 -250.306586)
		(end 91.80957 -250.544838)
		(width 0.18288)
		(layer "In2.Cu")
		(net "M_B_CPU1_CLK_DP<0>")
	)
	(segment
		(start 86.062058 -251.177044)
		(end 82.441542 -251.177044)
		(width 0.18288)
		(layer "In2.Cu")
		(net "M_B_CPU1_CLK_DP<0>")
	)
	(segment
		(start 82.441542 -251.177044)
		(end 79.078074 -254.540512)
		(width 0.18288)
		(layer "In2.Cu")
		(net "M_B_CPU1_CLK_DP<0>")
	)
	(segment
		(start 49.959514 -259.366766)
		(end 51.089814 -259.366766)
		(width 0.20066)
		(layer "F.Cu")
		(net "M_B_CPU1_CLK_DN<1>")
	)
	(segment
		(start 93.314266 -250.155964)
		(end 93.314266 -249.620278)
		(width 0.20066)
		(layer "F.Cu")
		(net "M_B_CPU1_CLK_DN<1>")
	)
	(segment
		(start 93.314266 -249.620278)
		(end 93.314012 -249.620024)
		(width 0.20066)
		(layer "F.Cu")
		(net "M_B_CPU1_CLK_DN<1>")
	)
	(segment
		(start 93.476572 -250.492006)
		(end 92.983812 -250.695968)
		(width 0.18288)
		(layer "In2.Cu")
		(net "M_B_CPU1_CLK_DN<1>")
	)
	(segment
		(start 92.983812 -250.695968)
		(end 92.824554 -250.630182)
		(width 0.18288)
		(layer "In2.Cu")
		(net "M_B_CPU1_CLK_DN<1>")
	)
	(segment
		(start 51.533552 -259.104384)
		(end 51.469544 -259.259324)
		(width 0.18288)
		(layer "In2.Cu")
		(net "M_B_CPU1_CLK_DN<1>")
	)
	(segment
		(start 64.699642 -256.224786)
		(end 59.15914 -256.224786)
		(width 0.18288)
		(layer "In2.Cu")
		(net "M_B_CPU1_CLK_DN<1>")
	)
	(segment
		(start 86.300564 -251.547122)
		(end 82.574892 -251.547122)
		(width 0.18288)
		(layer "In2.Cu")
		(net "M_B_CPU1_CLK_DN<1>")
	)
	(segment
		(start 56.486552 -256.798572)
		(end 55.727346 -256.961386)
		(width 0.18288)
		(layer "In2.Cu")
		(net "M_B_CPU1_CLK_DN<1>")
	)
	(segment
		(start 92.824554 -250.630182)
		(end 92.33154 -250.834144)
		(width 0.18288)
		(layer "In2.Cu")
		(net "M_B_CPU1_CLK_DN<1>")
	)
	(segment
		(start 67.689984 -255.629918)
		(end 67.546728 -255.53416)
		(width 0.18288)
		(layer "In2.Cu")
		(net "M_B_CPU1_CLK_DN<1>")
	)
	(segment
		(start 65.649856 -256.02565)
		(end 65.644522 -256.02692)
		(width 0.18288)
		(layer "In2.Cu")
		(net "M_B_CPU1_CLK_DN<1>")
	)
	(segment
		(start 65.73774 -255.894078)
		(end 65.649856 -256.02565)
		(width 0.18288)
		(layer "In2.Cu")
		(net "M_B_CPU1_CLK_DN<1>")
	)
	(segment
		(start 93.631512 -249.932444)
		(end 93.631512 -250.337066)
		(width 0.18288)
		(layer "In2.Cu")
		(net "M_B_CPU1_CLK_DN<1>")
	)
	(segment
		(start 55.06085 -256.979674)
		(end 54.967124 -257.124708)
		(width 0.18288)
		(layer "In2.Cu")
		(net "M_B_CPU1_CLK_DN<1>")
	)
	(segment
		(start 93.319092 -249.620024)
		(end 93.631512 -249.932444)
		(width 0.18288)
		(layer "In2.Cu")
		(net "M_B_CPU1_CLK_DN<1>")
	)
	(segment
		(start 58.637678 -256.336546)
		(end 58.492898 -256.243074)
		(width 0.18288)
		(layer "In2.Cu")
		(net "M_B_CPU1_CLK_DN<1>")
	)
	(segment
		(start 68.975478 -255.37414)
		(end 68.832222 -255.278382)
		(width 0.18288)
		(layer "In2.Cu")
		(net "M_B_CPU1_CLK_DN<1>")
	)
	(segment
		(start 53.374798 -257.466592)
		(end 52.421282 -257.671316)
		(width 0.18288)
		(layer "In2.Cu")
		(net "M_B_CPU1_CLK_DN<1>")
	)
	(segment
		(start 67.023234 -255.6383)
		(end 66.927476 -255.78181)
		(width 0.18288)
		(layer "In2.Cu")
		(net "M_B_CPU1_CLK_DN<1>")
	)
	(segment
		(start 82.574892 -251.547122)
		(end 79.225648 -254.896366)
		(width 0.18288)
		(layer "In2.Cu")
		(net "M_B_CPU1_CLK_DN<1>")
	)
	(segment
		(start 68.832222 -255.278382)
		(end 68.308728 -255.382522)
		(width 0.18288)
		(layer "In2.Cu")
		(net "M_B_CPU1_CLK_DN<1>")
	)
	(segment
		(start 51.362102 -259.366766)
		(end 51.089814 -259.366766)
		(width 0.18288)
		(layer "In2.Cu")
		(net "M_B_CPU1_CLK_DN<1>")
	)
	(segment
		(start 56.580278 -256.653538)
		(end 56.486552 -256.798572)
		(width 0.18288)
		(layer "In2.Cu")
		(net "M_B_CPU1_CLK_DN<1>")
	)
	(segment
		(start 92.2655 -250.993656)
		(end 91.625674 -251.258832)
		(width 0.18288)
		(layer "In2.Cu")
		(net "M_B_CPU1_CLK_DN<1>")
	)
	(segment
		(start 55.582566 -256.86766)
		(end 55.06085 -256.979674)
		(width 0.18288)
		(layer "In2.Cu")
		(net "M_B_CPU1_CLK_DN<1>")
	)
	(segment
		(start 51.822604 -257.875024)
		(end 51.533552 -258.278376)
		(width 0.18288)
		(layer "In2.Cu")
		(net "M_B_CPU1_CLK_DN<1>")
	)
	(segment
		(start 55.727346 -256.961386)
		(end 55.582566 -256.86766)
		(width 0.18288)
		(layer "In2.Cu")
		(net "M_B_CPU1_CLK_DN<1>")
	)
	(segment
		(start 68.21297 -255.526032)
		(end 67.689984 -255.629918)
		(width 0.18288)
		(layer "In2.Cu")
		(net "M_B_CPU1_CLK_DN<1>")
	)
	(segment
		(start 57.101994 -256.541524)
		(end 56.580278 -256.653538)
		(width 0.18288)
		(layer "In2.Cu")
		(net "M_B_CPU1_CLK_DN<1>")
	)
	(segment
		(start 93.631512 -250.337066)
		(end 93.476572 -250.492006)
		(width 0.18288)
		(layer "In2.Cu")
		(net "M_B_CPU1_CLK_DN<1>")
	)
	(segment
		(start 65.644522 -256.02692)
		(end 65.640712 -256.032254)
		(width 0.18288)
		(layer "In2.Cu")
		(net "M_B_CPU1_CLK_DN<1>")
	)
	(segment
		(start 92.33154 -250.834144)
		(end 92.2655 -250.993656)
		(width 0.18288)
		(layer "In2.Cu")
		(net "M_B_CPU1_CLK_DN<1>")
	)
	(segment
		(start 79.225648 -254.896366)
		(end 71.379588 -254.896366)
		(width 0.18288)
		(layer "In2.Cu")
		(net "M_B_CPU1_CLK_DN<1>")
	)
	(segment
		(start 66.40449 -255.885696)
		(end 66.26098 -255.789938)
		(width 0.18288)
		(layer "In2.Cu")
		(net "M_B_CPU1_CLK_DN<1>")
	)
	(segment
		(start 70.996048 -254.972566)
		(end 68.975478 -255.37414)
		(width 0.18288)
		(layer "In2.Cu")
		(net "M_B_CPU1_CLK_DN<1>")
	)
	(segment
		(start 58.492898 -256.243074)
		(end 57.971182 -256.354834)
		(width 0.18288)
		(layer "In2.Cu")
		(net "M_B_CPU1_CLK_DN<1>")
	)
	(segment
		(start 91.625674 -251.258832)
		(end 86.997032 -251.258832)
		(width 0.18288)
		(layer "In2.Cu")
		(net "M_B_CPU1_CLK_DN<1>")
	)
	(segment
		(start 52.421282 -257.671316)
		(end 51.822604 -257.875024)
		(width 0.18288)
		(layer "In2.Cu")
		(net "M_B_CPU1_CLK_DN<1>")
	)
	(segment
		(start 57.971182 -256.354834)
		(end 57.877456 -256.499868)
		(width 0.18288)
		(layer "In2.Cu")
		(net "M_B_CPU1_CLK_DN<1>")
	)
	(segment
		(start 86.997032 -251.258832)
		(end 86.300564 -251.547122)
		(width 0.18288)
		(layer "In2.Cu")
		(net "M_B_CPU1_CLK_DN<1>")
	)
	(segment
		(start 57.877456 -256.499868)
		(end 57.246774 -256.63525)
		(width 0.18288)
		(layer "In2.Cu")
		(net "M_B_CPU1_CLK_DN<1>")
	)
	(segment
		(start 57.246774 -256.63525)
		(end 57.101994 -256.541524)
		(width 0.18288)
		(layer "In2.Cu")
		(net "M_B_CPU1_CLK_DN<1>")
	)
	(segment
		(start 54.967124 -257.124708)
		(end 54.13502 -257.30327)
		(width 0.18288)
		(layer "In2.Cu")
		(net "M_B_CPU1_CLK_DN<1>")
	)
	(segment
		(start 53.99024 -257.209544)
		(end 53.468524 -257.321558)
		(width 0.18288)
		(layer "In2.Cu")
		(net "M_B_CPU1_CLK_DN<1>")
	)
	(segment
		(start 67.546728 -255.53416)
		(end 67.023234 -255.6383)
		(width 0.18288)
		(layer "In2.Cu")
		(net "M_B_CPU1_CLK_DN<1>")
	)
	(segment
		(start 66.927476 -255.78181)
		(end 66.40449 -255.885696)
		(width 0.18288)
		(layer "In2.Cu")
		(net "M_B_CPU1_CLK_DN<1>")
	)
	(segment
		(start 54.13502 -257.30327)
		(end 53.99024 -257.209544)
		(width 0.18288)
		(layer "In2.Cu")
		(net "M_B_CPU1_CLK_DN<1>")
	)
	(segment
		(start 53.468524 -257.321558)
		(end 53.374798 -257.466592)
		(width 0.18288)
		(layer "In2.Cu")
		(net "M_B_CPU1_CLK_DN<1>")
	)
	(segment
		(start 51.469544 -259.259324)
		(end 51.362102 -259.366766)
		(width 0.18288)
		(layer "In2.Cu")
		(net "M_B_CPU1_CLK_DN<1>")
	)
	(segment
		(start 93.314012 -249.620024)
		(end 93.319092 -249.620024)
		(width 0.18288)
		(layer "In2.Cu")
		(net "M_B_CPU1_CLK_DN<1>")
	)
	(segment
		(start 51.533552 -258.278376)
		(end 51.533552 -259.104384)
		(width 0.18288)
		(layer "In2.Cu")
		(net "M_B_CPU1_CLK_DN<1>")
	)
	(segment
		(start 65.637156 -256.038096)
		(end 64.699642 -256.224786)
		(width 0.18288)
		(layer "In2.Cu")
		(net "M_B_CPU1_CLK_DN<1>")
	)
	(segment
		(start 65.640712 -256.032254)
		(end 65.637156 -256.038096)
		(width 0.18288)
		(layer "In2.Cu")
		(net "M_B_CPU1_CLK_DN<1>")
	)
	(segment
		(start 59.15914 -256.224786)
		(end 58.637678 -256.336546)
		(width 0.18288)
		(layer "In2.Cu")
		(net "M_B_CPU1_CLK_DN<1>")
	)
	(segment
		(start 66.26098 -255.789938)
		(end 65.73774 -255.894078)
		(width 0.18288)
		(layer "In2.Cu")
		(net "M_B_CPU1_CLK_DN<1>")
	)
	(segment
		(start 68.308728 -255.382522)
		(end 68.21297 -255.526032)
		(width 0.18288)
		(layer "In2.Cu")
		(net "M_B_CPU1_CLK_DN<1>")
	)
	(segment
		(start 71.379588 -254.896366)
		(end 70.996048 -254.972566)
		(width 0.18288)
		(layer "In2.Cu")
		(net "M_B_CPU1_CLK_DN<1>")
	)
	(segment
		(start 42.415714 -259.366766)
		(end 43.520614 -259.366766)
		(width 0.20066)
		(layer "F.Cu")
		(net "M_B_CPU1_CLK_DN<0>")
	)
	(segment
		(start 91.434412 -250.15571)
		(end 91.434412 -249.620024)
		(width 0.20066)
		(layer "F.Cu")
		(net "M_B_CPU1_CLK_DN<0>")
	)
	(segment
		(start 91.434666 -250.155964)
		(end 91.434412 -250.15571)
		(width 0.20066)
		(layer "F.Cu")
		(net "M_B_CPU1_CLK_DN<0>")
	)
	(segment
		(start 48.89627 -257.302762)
		(end 47.37608 -257.302762)
		(width 0.18288)
		(layer "In2.Cu")
		(net "M_B_CPU1_CLK_DN<0>")
	)
	(segment
		(start 91.434412 -249.620024)
		(end 91.434412 -249.642884)
		(width 0.18288)
		(layer "In2.Cu")
		(net "M_B_CPU1_CLK_DN<0>")
	)
	(segment
		(start 46.59884 -257.302762)
		(end 46.06544 -257.302762)
		(width 0.18288)
		(layer "In2.Cu")
		(net "M_B_CPU1_CLK_DN<0>")
	)
	(segment
		(start 44.003976 -258.8387)
		(end 44.275248 -259.109972)
		(width 0.18288)
		(layer "In2.Cu")
		(net "M_B_CPU1_CLK_DN<0>")
	)
	(segment
		(start 51.755802 -256.590038)
		(end 51.23307 -256.69748)
		(width 0.18288)
		(layer "In2.Cu")
		(net "M_B_CPU1_CLK_DN<0>")
	)
	(segment
		(start 53.310028 -256.394966)
		(end 53.16601 -256.300224)
		(width 0.18288)
		(layer "In2.Cu")
		(net "M_B_CPU1_CLK_DN<0>")
	)
	(segment
		(start 53.16601 -256.300224)
		(end 52.643278 -256.407666)
		(width 0.18288)
		(layer "In2.Cu")
		(net "M_B_CPU1_CLK_DN<0>")
	)
	(segment
		(start 86.000336 -250.867164)
		(end 82.313018 -250.867164)
		(width 0.18288)
		(layer "In2.Cu")
		(net "M_B_CPU1_CLK_DN<0>")
	)
	(segment
		(start 51.138328 -256.841752)
		(end 50.2793 -257.018282)
		(width 0.18288)
		(layer "In2.Cu")
		(net "M_B_CPU1_CLK_DN<0>")
	)
	(segment
		(start 58.215784 -255.386586)
		(end 53.310028 -256.394966)
		(width 0.18288)
		(layer "In2.Cu")
		(net "M_B_CPU1_CLK_DN<0>")
	)
	(segment
		(start 49.61255 -257.030728)
		(end 49.517808 -257.175)
		(width 0.18288)
		(layer "In2.Cu")
		(net "M_B_CPU1_CLK_DN<0>")
	)
	(segment
		(start 91.737942 -250.178062)
		(end 91.633802 -250.281948)
		(width 0.18288)
		(layer "In2.Cu")
		(net "M_B_CPU1_CLK_DN<0>")
	)
	(segment
		(start 46.06544 -257.302762)
		(end 45.94352 -257.180842)
		(width 0.18288)
		(layer "In2.Cu")
		(net "M_B_CPU1_CLK_DN<0>")
	)
	(segment
		(start 49.517808 -257.175)
		(end 48.89627 -257.302762)
		(width 0.18288)
		(layer "In2.Cu")
		(net "M_B_CPU1_CLK_DN<0>")
	)
	(segment
		(start 47.25416 -257.180842)
		(end 46.72076 -257.180842)
		(width 0.18288)
		(layer "In2.Cu")
		(net "M_B_CPU1_CLK_DN<0>")
	)
	(segment
		(start 91.434412 -249.642884)
		(end 91.737942 -249.946414)
		(width 0.18288)
		(layer "In2.Cu")
		(net "M_B_CPU1_CLK_DN<0>")
	)
	(segment
		(start 87.188802 -250.374912)
		(end 86.000336 -250.867164)
		(width 0.18288)
		(layer "In2.Cu")
		(net "M_B_CPU1_CLK_DN<0>")
	)
	(segment
		(start 51.23307 -256.69748)
		(end 51.138328 -256.841752)
		(width 0.18288)
		(layer "In2.Cu")
		(net "M_B_CPU1_CLK_DN<0>")
	)
	(segment
		(start 82.313018 -250.867164)
		(end 78.94955 -254.230632)
		(width 0.18288)
		(layer "In2.Cu")
		(net "M_B_CPU1_CLK_DN<0>")
	)
	(segment
		(start 91.737942 -249.946414)
		(end 91.737942 -250.178062)
		(width 0.18288)
		(layer "In2.Cu")
		(net "M_B_CPU1_CLK_DN<0>")
	)
	(segment
		(start 46.72076 -257.180842)
		(end 46.59884 -257.302762)
		(width 0.18288)
		(layer "In2.Cu")
		(net "M_B_CPU1_CLK_DN<0>")
	)
	(segment
		(start 45.41012 -257.180842)
		(end 45.2882 -257.302762)
		(width 0.18288)
		(layer "In2.Cu")
		(net "M_B_CPU1_CLK_DN<0>")
	)
	(segment
		(start 50.135282 -256.92354)
		(end 49.61255 -257.030728)
		(width 0.18288)
		(layer "In2.Cu")
		(net "M_B_CPU1_CLK_DN<0>")
	)
	(segment
		(start 52.548536 -256.551684)
		(end 51.89982 -256.685034)
		(width 0.18288)
		(layer "In2.Cu")
		(net "M_B_CPU1_CLK_DN<0>")
	)
	(segment
		(start 91.633802 -250.281948)
		(end 91.409774 -250.374912)
		(width 0.18288)
		(layer "In2.Cu")
		(net "M_B_CPU1_CLK_DN<0>")
	)
	(segment
		(start 51.89982 -256.685034)
		(end 51.755802 -256.590038)
		(width 0.18288)
		(layer "In2.Cu")
		(net "M_B_CPU1_CLK_DN<0>")
	)
	(segment
		(start 45.2882 -257.302762)
		(end 44.7548 -257.302762)
		(width 0.18288)
		(layer "In2.Cu")
		(net "M_B_CPU1_CLK_DN<0>")
	)
	(segment
		(start 45.94352 -257.180842)
		(end 45.41012 -257.180842)
		(width 0.18288)
		(layer "In2.Cu")
		(net "M_B_CPU1_CLK_DN<0>")
	)
	(segment
		(start 50.2793 -257.018282)
		(end 50.135282 -256.92354)
		(width 0.18288)
		(layer "In2.Cu")
		(net "M_B_CPU1_CLK_DN<0>")
	)
	(segment
		(start 43.809666 -259.655818)
		(end 43.520614 -259.366766)
		(width 0.18288)
		(layer "In2.Cu")
		(net "M_B_CPU1_CLK_DN<0>")
	)
	(segment
		(start 44.7548 -257.302762)
		(end 44.003976 -258.053586)
		(width 0.18288)
		(layer "In2.Cu")
		(net "M_B_CPU1_CLK_DN<0>")
	)
	(segment
		(start 63.419228 -255.386586)
		(end 58.215784 -255.386586)
		(width 0.18288)
		(layer "In2.Cu")
		(net "M_B_CPU1_CLK_DN<0>")
	)
	(segment
		(start 91.409774 -250.374912)
		(end 87.188802 -250.374912)
		(width 0.18288)
		(layer "In2.Cu")
		(net "M_B_CPU1_CLK_DN<0>")
	)
	(segment
		(start 44.003976 -258.053586)
		(end 44.003976 -258.8387)
		(width 0.18288)
		(layer "In2.Cu")
		(net "M_B_CPU1_CLK_DN<0>")
	)
	(segment
		(start 44.275248 -259.456936)
		(end 44.076366 -259.655818)
		(width 0.18288)
		(layer "In2.Cu")
		(net "M_B_CPU1_CLK_DN<0>")
	)
	(segment
		(start 78.94955 -254.230632)
		(end 69.118226 -254.230632)
		(width 0.18288)
		(layer "In2.Cu")
		(net "M_B_CPU1_CLK_DN<0>")
	)
	(segment
		(start 44.275248 -259.109972)
		(end 44.275248 -259.456936)
		(width 0.18288)
		(layer "In2.Cu")
		(net "M_B_CPU1_CLK_DN<0>")
	)
	(segment
		(start 69.118226 -254.230632)
		(end 63.419228 -255.386586)
		(width 0.18288)
		(layer "In2.Cu")
		(net "M_B_CPU1_CLK_DN<0>")
	)
	(segment
		(start 47.37608 -257.302762)
		(end 47.25416 -257.180842)
		(width 0.18288)
		(layer "In2.Cu")
		(net "M_B_CPU1_CLK_DN<0>")
	)
	(segment
		(start 52.643278 -256.407666)
		(end 52.548536 -256.551684)
		(width 0.18288)
		(layer "In2.Cu")
		(net "M_B_CPU1_CLK_DN<0>")
	)
	(segment
		(start 44.076366 -259.655818)
		(end 43.809666 -259.655818)
		(width 0.18288)
		(layer "In2.Cu")
		(net "M_B_CPU1_CLK_DN<0>")
	)
	(segment
		(start 40.682672 -269.141702)
		(end 40.520112 -269.304262)
		(width 0.20066)
		(layer "F.Cu")
		(net "M_B_CPU1_ALERT_N")
	)
	(segment
		(start 39.861236 -269.777972)
		(end 39.649908 -269.566644)
		(width 0.20066)
		(layer "F.Cu")
		(net "M_B_CPU1_ALERT_N")
	)
	(segment
		(start 102.352094 -255.011682)
		(end 102.352348 -255.011936)
		(width 0.20066)
		(layer "F.Cu")
		(net "M_B_CPU1_ALERT_N")
	)
	(segment
		(start 39.649908 -269.566644)
		(end 38.315646 -269.566644)
		(width 0.20066)
		(layer "F.Cu")
		(net "M_B_CPU1_ALERT_N")
	)
	(segment
		(start 43.69054 -269.141702)
		(end 43.285918 -269.141702)
		(width 0.101854)
		(layer "F.Cu")
		(net "M_B_CPU1_ALERT_N")
	)
	(segment
		(start 44.22013 -269.566644)
		(end 43.795188 -269.141702)
		(width 0.20066)
		(layer "F.Cu")
		(net "M_B_CPU1_ALERT_N")
	)
	(segment
		(start 41.3004 -269.141702)
		(end 41.157652 -269.141702)
		(width 0.101854)
		(layer "F.Cu")
		(net "M_B_CPU1_ALERT_N")
	)
	(segment
		(start 43.795188 -269.141702)
		(end 43.69054 -269.141702)
		(width 0.20066)
		(layer "F.Cu")
		(net "M_B_CPU1_ALERT_N")
	)
	(segment
		(start 40.520112 -269.304262)
		(end 40.520112 -269.62354)
		(width 0.20066)
		(layer "F.Cu")
		(net "M_B_CPU1_ALERT_N")
	)
	(segment
		(start 102.352348 -255.011936)
		(end 102.352348 -255.547622)
		(width 0.20066)
		(layer "F.Cu")
		(net "M_B_CPU1_ALERT_N")
	)
	(segment
		(start 40.520112 -269.62354)
		(end 40.36568 -269.777972)
		(width 0.20066)
		(layer "F.Cu")
		(net "M_B_CPU1_ALERT_N")
	)
	(segment
		(start 45.859446 -269.566644)
		(end 44.22013 -269.566644)
		(width 0.20066)
		(layer "F.Cu")
		(net "M_B_CPU1_ALERT_N")
	)
	(segment
		(start 46.964346 -269.566644)
		(end 45.859446 -269.566644)
		(width 0.20066)
		(layer "F.Cu")
		(net "M_B_CPU1_ALERT_N")
	)
	(segment
		(start 41.157652 -269.141702)
		(end 40.682672 -269.141702)
		(width 0.20066)
		(layer "F.Cu")
		(net "M_B_CPU1_ALERT_N")
	)
	(segment
		(start 43.285918 -269.141702)
		(end 41.3004 -269.141702)
		(width 0.1016)
		(layer "F.Cu")
		(net "M_B_CPU1_ALERT_N")
	)
	(segment
		(start 40.36568 -269.777972)
		(end 39.861236 -269.777972)
		(width 0.20066)
		(layer "F.Cu")
		(net "M_B_CPU1_ALERT_N")
	)
	(via
		(at 102.352348 -255.547622)
		(size 0.4572)
		(drill 0.2032)
		(layers "F.Cu" "B.Cu")
		(net "M_B_CPU1_ALERT_N")
	)
	(via
		(at 93.423994 -254.733552)
		(size 0.4318)
		(drill 0.2032)
		(layers "F.Cu" "B.Cu")
		(net "M_B_CPU1_ALERT_N")
	)
	(via
		(at 46.964346 -269.566644)
		(size 0.4572)
		(drill 0.2032)
		(layers "F.Cu" "B.Cu")
		(net "M_B_CPU1_ALERT_N")
	)
	(segment
		(start 96.48825 -255.135126)
		(end 96.478598 -255.140714)
		(width 0.20066)
		(layer "B.Cu")
		(net "M_B_CPU1_ALERT_N")
	)
	(segment
		(start 102.352348 -255.547622)
		(end 102.3493 -255.536446)
		(width 0.20066)
		(layer "B.Cu")
		(net "M_B_CPU1_ALERT_N")
	)
	(segment
		(start 96.957896 -255.146302)
		(end 96.948244 -255.140714)
		(width 0.20066)
		(layer "B.Cu")
		(net "M_B_CPU1_ALERT_N")
	)
	(segment
		(start 94.62516 -255.125728)
		(end 94.598998 -255.140714)
		(width 0.20066)
		(layer "B.Cu")
		(net "M_B_CPU1_ALERT_N")
	)
	(segment
		(start 102.3493 -255.536446)
		(end 101.663754 -255.14046)
		(width 0.20066)
		(layer "B.Cu")
		(net "M_B_CPU1_ALERT_N")
	)
	(segment
		(start 98.412046 -255.109472)
		(end 98.358198 -255.140714)
		(width 0.20066)
		(layer "B.Cu")
		(net "M_B_CPU1_ALERT_N")
	)
	(segment
		(start 95.078296 -255.146302)
		(end 95.042482 -255.125728)
		(width 0.20066)
		(layer "B.Cu")
		(net "M_B_CPU1_ALERT_N")
	)
	(segment
		(start 101.177344 -255.14046)
		(end 101.151182 -255.155446)
		(width 0.20066)
		(layer "B.Cu")
		(net "M_B_CPU1_ALERT_N")
	)
	(segment
		(start 98.828098 -255.14046)
		(end 98.818446 -255.134872)
		(width 0.20066)
		(layer "B.Cu")
		(net "M_B_CPU1_ALERT_N")
	)
	(segment
		(start 97.90176 -255.148588)
		(end 97.888298 -255.140714)
		(width 0.20066)
		(layer "B.Cu")
		(net "M_B_CPU1_ALERT_N")
	)
	(segment
		(start 99.297744 -255.14046)
		(end 99.288092 -255.146048)
		(width 0.20066)
		(layer "B.Cu")
		(net "M_B_CPU1_ALERT_N")
	)
	(segment
		(start 100.73386 -255.155446)
		(end 100.698046 -255.134872)
		(width 0.20066)
		(layer "B.Cu")
		(net "M_B_CPU1_ALERT_N")
	)
	(segment
		(start 94.112588 -255.140714)
		(end 93.427042 -254.744728)
		(width 0.20066)
		(layer "B.Cu")
		(net "M_B_CPU1_ALERT_N")
	)
	(segment
		(start 93.427042 -254.744728)
		(end 93.423994 -254.733552)
		(width 0.20066)
		(layer "B.Cu")
		(net "M_B_CPU1_ALERT_N")
	)
	(segment
		(start 98.675444 -255.07569)
		(end 98.538538 -255.07569)
		(width 0.20066)
		(layer "B.Cu")
		(net "M_B_CPU1_ALERT_N")
	)
	(arc
		(start 98.358198 -255.140714)
		(mid 98.131011 -255.203698)
		(end 97.90176 -255.148588)
		(width 0.20066)
		(layer "B.Cu")
		(net "M_B_CPU1_ALERT_N")
	)
	(arc
		(start 99.767644 -255.14046)
		(mid 99.532694 -255.077534)
		(end 99.297744 -255.14046)
		(width 0.20066)
		(layer "B.Cu")
		(net "M_B_CPU1_ALERT_N")
	)
	(arc
		(start 95.538798 -255.140714)
		(mid 95.309281 -255.203732)
		(end 95.078296 -255.146302)
		(width 0.20066)
		(layer "B.Cu")
		(net "M_B_CPU1_ALERT_N")
	)
	(arc
		(start 99.288092 -255.146048)
		(mid 99.057361 -255.203409)
		(end 98.828098 -255.14046)
		(width 0.20066)
		(layer "B.Cu")
		(net "M_B_CPU1_ALERT_N")
	)
	(arc
		(start 101.663754 -255.14046)
		(mid 101.420532 -255.075249)
		(end 101.177344 -255.14046)
		(width 0.20066)
		(layer "B.Cu")
		(net "M_B_CPU1_ALERT_N")
	)
	(arc
		(start 96.948244 -255.140714)
		(mid 96.718981 -255.077789)
		(end 96.48825 -255.135126)
		(width 0.20066)
		(layer "B.Cu")
		(net "M_B_CPU1_ALERT_N")
	)
	(arc
		(start 98.818446 -255.134872)
		(mid 98.752836 -255.091033)
		(end 98.675444 -255.07569)
		(width 0.20066)
		(layer "B.Cu")
		(net "M_B_CPU1_ALERT_N")
	)
	(arc
		(start 97.418398 -255.140714)
		(mid 97.188881 -255.203732)
		(end 96.957896 -255.146302)
		(width 0.20066)
		(layer "B.Cu")
		(net "M_B_CPU1_ALERT_N")
	)
	(arc
		(start 96.478598 -255.140714)
		(mid 96.243648 -255.20364)
		(end 96.008698 -255.140714)
		(width 0.20066)
		(layer "B.Cu")
		(net "M_B_CPU1_ALERT_N")
	)
	(arc
		(start 95.042482 -255.125728)
		(mid 94.833838 -255.069749)
		(end 94.62516 -255.125728)
		(width 0.20066)
		(layer "B.Cu")
		(net "M_B_CPU1_ALERT_N")
	)
	(arc
		(start 97.888298 -255.140714)
		(mid 97.653348 -255.077754)
		(end 97.418398 -255.140714)
		(width 0.20066)
		(layer "B.Cu")
		(net "M_B_CPU1_ALERT_N")
	)
	(arc
		(start 100.237544 -255.14046)
		(mid 100.002594 -255.20342)
		(end 99.767644 -255.14046)
		(width 0.20066)
		(layer "B.Cu")
		(net "M_B_CPU1_ALERT_N")
	)
	(arc
		(start 98.538538 -255.07569)
		(mid 98.473067 -255.084249)
		(end 98.412046 -255.109472)
		(width 0.20066)
		(layer "B.Cu")
		(net "M_B_CPU1_ALERT_N")
	)
	(arc
		(start 100.698046 -255.134872)
		(mid 100.467061 -255.077421)
		(end 100.237544 -255.14046)
		(width 0.20066)
		(layer "B.Cu")
		(net "M_B_CPU1_ALERT_N")
	)
	(arc
		(start 101.151182 -255.155446)
		(mid 100.942538 -255.211425)
		(end 100.73386 -255.155446)
		(width 0.20066)
		(layer "B.Cu")
		(net "M_B_CPU1_ALERT_N")
	)
	(arc
		(start 96.008698 -255.140714)
		(mid 95.773748 -255.077754)
		(end 95.538798 -255.140714)
		(width 0.20066)
		(layer "B.Cu")
		(net "M_B_CPU1_ALERT_N")
	)
	(arc
		(start 94.598998 -255.140714)
		(mid 94.355776 -255.205925)
		(end 94.112588 -255.140714)
		(width 0.20066)
		(layer "B.Cu")
		(net "M_B_CPU1_ALERT_N")
	)
	(segment
		(start 61.805058 -267.457428)
		(end 61.58992 -267.24229)
		(width 0.18288)
		(layer "In2.Cu")
		(net "M_B_CPU1_ALERT_N")
	)
	(segment
		(start 83.372198 -257.543554)
		(end 81.218786 -259.696966)
		(width 0.18288)
		(layer "In2.Cu")
		(net "M_B_CPU1_ALERT_N")
	)
	(segment
		(start 83.62315 -257.543554)
		(end 83.372198 -257.543554)
		(width 0.18288)
		(layer "In2.Cu")
		(net "M_B_CPU1_ALERT_N")
	)
	(segment
		(start 47.446438 -269.084552)
		(end 46.964346 -269.566644)
		(width 0.18288)
		(layer "In2.Cu")
		(net "M_B_CPU1_ALERT_N")
	)
	(segment
		(start 65.706244 -266.40917)
		(end 64.354964 -266.40917)
		(width 0.18288)
		(layer "In2.Cu")
		(net "M_B_CPU1_ALERT_N")
	)
	(segment
		(start 92.920566 -254.942086)
		(end 92.705682 -255.156716)
		(width 0.088646)
		(layer "In2.Cu")
		(net "M_B_CPU1_ALERT_N")
	)
	(segment
		(start 54.679342 -269.932912)
		(end 52.044346 -269.932912)
		(width 0.18288)
		(layer "In2.Cu")
		(net "M_B_CPU1_ALERT_N")
	)
	(segment
		(start 84.495894 -257.740404)
		(end 84.169504 -257.740404)
		(width 0.088646)
		(layer "In2.Cu")
		(net "M_B_CPU1_ALERT_N")
	)
	(segment
		(start 89.852246 -257.664712)
		(end 89.851992 -257.664712)
		(width 0.088646)
		(layer "In2.Cu")
		(net "M_B_CPU1_ALERT_N")
	)
	(segment
		(start 90.699844 -257.175254)
		(end 90.699844 -257.190748)
		(width 0.088646)
		(layer "In2.Cu")
		(net "M_B_CPU1_ALERT_N")
	)
	(segment
		(start 66.30543 -266.625324)
		(end 65.922398 -266.625324)
		(width 0.18288)
		(layer "In2.Cu")
		(net "M_B_CPU1_ALERT_N")
	)
	(segment
		(start 91.639898 -255.538986)
		(end 91.639898 -255.547622)
		(width 0.088646)
		(layer "In2.Cu")
		(net "M_B_CPU1_ALERT_N")
	)
	(segment
		(start 91.363292 -256.033524)
		(end 91.357196 -256.03708)
		(width 0.088646)
		(layer "In2.Cu")
		(net "M_B_CPU1_ALERT_N")
	)
	(segment
		(start 81.218786 -259.696966)
		(end 76.51369 -259.696966)
		(width 0.18288)
		(layer "In2.Cu")
		(net "M_B_CPU1_ALERT_N")
	)
	(segment
		(start 56.303164 -268.30909)
		(end 54.679342 -269.932912)
		(width 0.18288)
		(layer "In2.Cu")
		(net "M_B_CPU1_ALERT_N")
	)
	(segment
		(start 61.58992 -267.24229)
		(end 60.328556 -267.24229)
		(width 0.18288)
		(layer "In2.Cu")
		(net "M_B_CPU1_ALERT_N")
	)
	(segment
		(start 63.088774 -266.625324)
		(end 62.25667 -267.457428)
		(width 0.18288)
		(layer "In2.Cu")
		(net "M_B_CPU1_ALERT_N")
	)
	(segment
		(start 91.169744 -256.361438)
		(end 91.169744 -256.371344)
		(width 0.088646)
		(layer "In2.Cu")
		(net "M_B_CPU1_ALERT_N")
	)
	(segment
		(start 90.887296 -256.850896)
		(end 90.878406 -256.855976)
		(width 0.088646)
		(layer "In2.Cu")
		(net "M_B_CPU1_ALERT_N")
	)
	(segment
		(start 76.51369 -259.696966)
		(end 75.486514 -260.724142)
		(width 0.18288)
		(layer "In2.Cu")
		(net "M_B_CPU1_ALERT_N")
	)
	(segment
		(start 75.486514 -260.724142)
		(end 69.446902 -263.225788)
		(width 0.18288)
		(layer "In2.Cu")
		(net "M_B_CPU1_ALERT_N")
	)
	(segment
		(start 52.044346 -269.932912)
		(end 51.195986 -269.084552)
		(width 0.18288)
		(layer "In2.Cu")
		(net "M_B_CPU1_ALERT_N")
	)
	(segment
		(start 84.169504 -257.740404)
		(end 83.972654 -257.543554)
		(width 0.088646)
		(layer "In2.Cu")
		(net "M_B_CPU1_ALERT_N")
	)
	(segment
		(start 83.972654 -257.543554)
		(end 83.62315 -257.543554)
		(width 0.088646)
		(layer "In2.Cu")
		(net "M_B_CPU1_ALERT_N")
	)
	(segment
		(start 60.328556 -267.24229)
		(end 60.113418 -267.457428)
		(width 0.18288)
		(layer "In2.Cu")
		(net "M_B_CPU1_ALERT_N")
	)
	(segment
		(start 66.752978 -265.919712)
		(end 66.752978 -266.177776)
		(width 0.18288)
		(layer "In2.Cu")
		(net "M_B_CPU1_ALERT_N")
	)
	(segment
		(start 91.357196 -256.03708)
		(end 91.348306 -256.04216)
		(width 0.088646)
		(layer "In2.Cu")
		(net "M_B_CPU1_ALERT_N")
	)
	(segment
		(start 51.195986 -269.084552)
		(end 47.446438 -269.084552)
		(width 0.18288)
		(layer "In2.Cu")
		(net "M_B_CPU1_ALERT_N")
	)
	(segment
		(start 59.641486 -267.457428)
		(end 58.789824 -268.30909)
		(width 0.18288)
		(layer "In2.Cu")
		(net "M_B_CPU1_ALERT_N")
	)
	(segment
		(start 62.25667 -267.457428)
		(end 61.805058 -267.457428)
		(width 0.18288)
		(layer "In2.Cu")
		(net "M_B_CPU1_ALERT_N")
	)
	(segment
		(start 64.13881 -266.625324)
		(end 63.088774 -266.625324)
		(width 0.18288)
		(layer "In2.Cu")
		(net "M_B_CPU1_ALERT_N")
	)
	(segment
		(start 65.922398 -266.625324)
		(end 65.706244 -266.40917)
		(width 0.18288)
		(layer "In2.Cu")
		(net "M_B_CPU1_ALERT_N")
	)
	(segment
		(start 69.446902 -263.225788)
		(end 66.752978 -265.919712)
		(width 0.18288)
		(layer "In2.Cu")
		(net "M_B_CPU1_ALERT_N")
	)
	(segment
		(start 58.789824 -268.30909)
		(end 56.303164 -268.30909)
		(width 0.18288)
		(layer "In2.Cu")
		(net "M_B_CPU1_ALERT_N")
	)
	(segment
		(start 60.113418 -267.457428)
		(end 59.641486 -267.457428)
		(width 0.18288)
		(layer "In2.Cu")
		(net "M_B_CPU1_ALERT_N")
	)
	(segment
		(start 64.354964 -266.40917)
		(end 64.13881 -266.625324)
		(width 0.18288)
		(layer "In2.Cu")
		(net "M_B_CPU1_ALERT_N")
	)
	(segment
		(start 66.752978 -266.177776)
		(end 66.30543 -266.625324)
		(width 0.18288)
		(layer "In2.Cu")
		(net "M_B_CPU1_ALERT_N")
	)
	(arc
		(start 91.348306 -256.04216)
		(mid 91.217392 -256.17852)
		(end 91.169744 -256.361438)
		(width 0.088646)
		(layer "In2.Cu")
		(net "M_B_CPU1_ALERT_N")
	)
	(arc
		(start 89.477596 -257.664712)
		(mid 89.194894 -257.740488)
		(end 88.912192 -257.664712)
		(width 0.088646)
		(layer "In2.Cu")
		(net "M_B_CPU1_ALERT_N")
	)
	(arc
		(start 86.658196 -257.664712)
		(mid 86.375494 -257.740488)
		(end 86.092792 -257.664712)
		(width 0.088646)
		(layer "In2.Cu")
		(net "M_B_CPU1_ALERT_N")
	)
	(arc
		(start 86.092792 -257.664712)
		(mid 85.905594 -257.614569)
		(end 85.718396 -257.664712)
		(width 0.088646)
		(layer "In2.Cu")
		(net "M_B_CPU1_ALERT_N")
	)
	(arc
		(start 90.41765 -257.664712)
		(mid 90.134948 -257.740488)
		(end 89.852246 -257.664712)
		(width 0.088646)
		(layer "In2.Cu")
		(net "M_B_CPU1_ALERT_N")
	)
	(arc
		(start 88.912192 -257.664712)
		(mid 88.724994 -257.614569)
		(end 88.537796 -257.664712)
		(width 0.088646)
		(layer "In2.Cu")
		(net "M_B_CPU1_ALERT_N")
	)
	(arc
		(start 90.878406 -256.855976)
		(mid 90.747492 -256.992336)
		(end 90.699844 -257.175254)
		(width 0.088646)
		(layer "In2.Cu")
		(net "M_B_CPU1_ALERT_N")
	)
	(arc
		(start 85.152992 -257.664712)
		(mid 84.965794 -257.614569)
		(end 84.778596 -257.664712)
		(width 0.088646)
		(layer "In2.Cu")
		(net "M_B_CPU1_ALERT_N")
	)
	(arc
		(start 84.778596 -257.664712)
		(mid 84.642227 -257.721154)
		(end 84.495894 -257.740404)
		(width 0.088646)
		(layer "In2.Cu")
		(net "M_B_CPU1_ALERT_N")
	)
	(arc
		(start 89.851992 -257.664712)
		(mid 89.664794 -257.614569)
		(end 89.477596 -257.664712)
		(width 0.088646)
		(layer "In2.Cu")
		(net "M_B_CPU1_ALERT_N")
	)
	(arc
		(start 92.705682 -255.156716)
		(mid 92.464888 -255.275491)
		(end 92.201492 -255.223264)
		(width 0.088646)
		(layer "In2.Cu")
		(net "M_B_CPU1_ALERT_N")
	)
	(arc
		(start 87.972392 -257.664712)
		(mid 87.785194 -257.614569)
		(end 87.597996 -257.664712)
		(width 0.088646)
		(layer "In2.Cu")
		(net "M_B_CPU1_ALERT_N")
	)
	(arc
		(start 92.201492 -255.223264)
		(mid 92.014294 -255.173121)
		(end 91.827096 -255.223264)
		(width 0.088646)
		(layer "In2.Cu")
		(net "M_B_CPU1_ALERT_N")
	)
	(arc
		(start 90.699844 -257.190748)
		(mid 90.620474 -257.464482)
		(end 90.41765 -257.664712)
		(width 0.088646)
		(layer "In2.Cu")
		(net "M_B_CPU1_ALERT_N")
	)
	(arc
		(start 91.827096 -255.223264)
		(mid 91.692163 -255.356618)
		(end 91.639898 -255.538986)
		(width 0.088646)
		(layer "In2.Cu")
		(net "M_B_CPU1_ALERT_N")
	)
	(arc
		(start 91.639898 -255.547622)
		(mid 91.565907 -255.827188)
		(end 91.363292 -256.033524)
		(width 0.088646)
		(layer "In2.Cu")
		(net "M_B_CPU1_ALERT_N")
	)
	(arc
		(start 87.597996 -257.664712)
		(mid 87.315294 -257.740488)
		(end 87.032592 -257.664712)
		(width 0.088646)
		(layer "In2.Cu")
		(net "M_B_CPU1_ALERT_N")
	)
	(arc
		(start 87.032592 -257.664712)
		(mid 86.845394 -257.614569)
		(end 86.658196 -257.664712)
		(width 0.088646)
		(layer "In2.Cu")
		(net "M_B_CPU1_ALERT_N")
	)
	(arc
		(start 85.718396 -257.664712)
		(mid 85.435694 -257.740488)
		(end 85.152992 -257.664712)
		(width 0.088646)
		(layer "In2.Cu")
		(net "M_B_CPU1_ALERT_N")
	)
	(arc
		(start 88.537796 -257.664712)
		(mid 88.255094 -257.740488)
		(end 87.972392 -257.664712)
		(width 0.088646)
		(layer "In2.Cu")
		(net "M_B_CPU1_ALERT_N")
	)
	(arc
		(start 93.423994 -254.733552)
		(mid 93.151538 -254.787747)
		(end 92.920566 -254.942086)
		(width 0.088646)
		(layer "In2.Cu")
		(net "M_B_CPU1_ALERT_N")
	)
	(arc
		(start 91.169744 -256.371344)
		(mid 91.091633 -256.648293)
		(end 90.887296 -256.850896)
		(width 0.088646)
		(layer "In2.Cu")
		(net "M_B_CPU1_ALERT_N")
	)
	(segment
		(start 294.904414 -243.216684)
		(end 293.799514 -243.216684)
		(width 0.20066)
		(layer "F.Cu")
		(net "M_B_CPU0_SB_RSP<1>")
	)
	(segment
		(start 348.412562 -253.383796)
		(end 348.412562 -253.919482)
		(width 0.20066)
		(layer "F.Cu")
		(net "M_B_CPU0_SB_RSP<1>")
	)
	(segment
		(start 348.412562 -253.919482)
		(end 348.412816 -253.919736)
		(width 0.20066)
		(layer "F.Cu")
		(net "M_B_CPU0_SB_RSP<1>")
	)
	(segment
		(start 310.966104 -248.012204)
		(end 310.124856 -248.853452)
		(width 0.18288)
		(layer "In6.Cu")
		(net "M_B_CPU0_SB_RSP<1>")
	)
	(segment
		(start 302.422814 -245.93931)
		(end 301.99457 -246.367554)
		(width 0.18288)
		(layer "In6.Cu")
		(net "M_B_CPU0_SB_RSP<1>")
	)
	(segment
		(start 327.372726 -248.32056)
		(end 323.228462 -248.32056)
		(width 0.18288)
		(layer "In6.Cu")
		(net "M_B_CPU0_SB_RSP<1>")
	)
	(segment
		(start 348.059248 -252.781308)
		(end 348.059248 -252.32868)
		(width 0.18288)
		(layer "In6.Cu")
		(net "M_B_CPU0_SB_RSP<1>")
	)
	(segment
		(start 308.147466 -247.7262)
		(end 307.311806 -246.89054)
		(width 0.18288)
		(layer "In6.Cu")
		(net "M_B_CPU0_SB_RSP<1>")
	)
	(segment
		(start 305.152552 -246.73052)
		(end 304.992532 -246.89054)
		(width 0.18288)
		(layer "In6.Cu")
		(net "M_B_CPU0_SB_RSP<1>")
	)
	(segment
		(start 305.685952 -246.243856)
		(end 305.312572 -246.243856)
		(width 0.18288)
		(layer "In6.Cu")
		(net "M_B_CPU0_SB_RSP<1>")
	)
	(segment
		(start 301.000922 -244.817646)
		(end 301.000922 -243.796058)
		(width 0.18288)
		(layer "In6.Cu")
		(net "M_B_CPU0_SB_RSP<1>")
	)
	(segment
		(start 316.007242 -250.354846)
		(end 314.362846 -248.71045)
		(width 0.18288)
		(layer "In6.Cu")
		(net "M_B_CPU0_SB_RSP<1>")
	)
	(segment
		(start 310.124856 -248.853452)
		(end 309.586122 -248.853452)
		(width 0.18288)
		(layer "In6.Cu")
		(net "M_B_CPU0_SB_RSP<1>")
	)
	(segment
		(start 301.76851 -246.367554)
		(end 300.722792 -245.321836)
		(width 0.18288)
		(layer "In6.Cu")
		(net "M_B_CPU0_SB_RSP<1>")
	)
	(segment
		(start 305.312572 -246.243856)
		(end 305.152552 -246.403876)
		(width 0.18288)
		(layer "In6.Cu")
		(net "M_B_CPU0_SB_RSP<1>")
	)
	(segment
		(start 300.722792 -245.321836)
		(end 300.722792 -245.095776)
		(width 0.18288)
		(layer "In6.Cu")
		(net "M_B_CPU0_SB_RSP<1>")
	)
	(segment
		(start 309.258208 -248.191274)
		(end 308.793134 -247.7262)
		(width 0.18288)
		(layer "In6.Cu")
		(net "M_B_CPU0_SB_RSP<1>")
	)
	(segment
		(start 348.059248 -252.32868)
		(end 346.600526 -250.869958)
		(width 0.18288)
		(layer "In6.Cu")
		(net "M_B_CPU0_SB_RSP<1>")
	)
	(segment
		(start 348.412816 -253.919736)
		(end 348.059248 -253.566168)
		(width 0.088646)
		(layer "In6.Cu")
		(net "M_B_CPU0_SB_RSP<1>")
	)
	(segment
		(start 329.922124 -250.869958)
		(end 327.372726 -248.32056)
		(width 0.18288)
		(layer "In6.Cu")
		(net "M_B_CPU0_SB_RSP<1>")
	)
	(segment
		(start 309.586122 -248.853452)
		(end 309.258208 -248.525538)
		(width 0.18288)
		(layer "In6.Cu")
		(net "M_B_CPU0_SB_RSP<1>")
	)
	(segment
		(start 309.258208 -248.525538)
		(end 309.258208 -248.191274)
		(width 0.18288)
		(layer "In6.Cu")
		(net "M_B_CPU0_SB_RSP<1>")
	)
	(segment
		(start 312.677048 -248.012204)
		(end 310.966104 -248.012204)
		(width 0.18288)
		(layer "In6.Cu")
		(net "M_B_CPU0_SB_RSP<1>")
	)
	(segment
		(start 297.555666 -244.378226)
		(end 297.381422 -244.55247)
		(width 0.18288)
		(layer "In6.Cu")
		(net "M_B_CPU0_SB_RSP<1>")
	)
	(segment
		(start 316.952376 -250.74626)
		(end 316.007242 -250.354846)
		(width 0.18288)
		(layer "In6.Cu")
		(net "M_B_CPU0_SB_RSP<1>")
	)
	(segment
		(start 300.722792 -245.095776)
		(end 301.000922 -244.817646)
		(width 0.18288)
		(layer "In6.Cu")
		(net "M_B_CPU0_SB_RSP<1>")
	)
	(segment
		(start 348.059248 -253.566168)
		(end 348.059248 -252.781308)
		(width 0.088646)
		(layer "In6.Cu")
		(net "M_B_CPU0_SB_RSP<1>")
	)
	(segment
		(start 307.311806 -246.89054)
		(end 306.005992 -246.89054)
		(width 0.18288)
		(layer "In6.Cu")
		(net "M_B_CPU0_SB_RSP<1>")
	)
	(segment
		(start 305.845972 -246.73052)
		(end 305.845972 -246.403876)
		(width 0.18288)
		(layer "In6.Cu")
		(net "M_B_CPU0_SB_RSP<1>")
	)
	(segment
		(start 305.152552 -246.403876)
		(end 305.152552 -246.73052)
		(width 0.18288)
		(layer "In6.Cu")
		(net "M_B_CPU0_SB_RSP<1>")
	)
	(segment
		(start 301.000922 -243.796058)
		(end 300.849284 -243.64442)
		(width 0.18288)
		(layer "In6.Cu")
		(net "M_B_CPU0_SB_RSP<1>")
	)
	(segment
		(start 300.849284 -243.64442)
		(end 297.684444 -243.64442)
		(width 0.18288)
		(layer "In6.Cu")
		(net "M_B_CPU0_SB_RSP<1>")
	)
	(segment
		(start 308.793134 -247.7262)
		(end 308.147466 -247.7262)
		(width 0.18288)
		(layer "In6.Cu")
		(net "M_B_CPU0_SB_RSP<1>")
	)
	(segment
		(start 302.956722 -245.93931)
		(end 302.422814 -245.93931)
		(width 0.18288)
		(layer "In6.Cu")
		(net "M_B_CPU0_SB_RSP<1>")
	)
	(segment
		(start 296.2402 -244.55247)
		(end 294.904414 -243.216684)
		(width 0.18288)
		(layer "In6.Cu")
		(net "M_B_CPU0_SB_RSP<1>")
	)
	(segment
		(start 314.362846 -248.71045)
		(end 312.677048 -248.012204)
		(width 0.18288)
		(layer "In6.Cu")
		(net "M_B_CPU0_SB_RSP<1>")
	)
	(segment
		(start 305.845972 -246.403876)
		(end 305.685952 -246.243856)
		(width 0.18288)
		(layer "In6.Cu")
		(net "M_B_CPU0_SB_RSP<1>")
	)
	(segment
		(start 323.228462 -248.32056)
		(end 320.802762 -250.74626)
		(width 0.18288)
		(layer "In6.Cu")
		(net "M_B_CPU0_SB_RSP<1>")
	)
	(segment
		(start 297.381422 -244.55247)
		(end 296.2402 -244.55247)
		(width 0.18288)
		(layer "In6.Cu")
		(net "M_B_CPU0_SB_RSP<1>")
	)
	(segment
		(start 297.555666 -243.773198)
		(end 297.555666 -244.378226)
		(width 0.18288)
		(layer "In6.Cu")
		(net "M_B_CPU0_SB_RSP<1>")
	)
	(segment
		(start 346.600526 -250.869958)
		(end 329.922124 -250.869958)
		(width 0.18288)
		(layer "In6.Cu")
		(net "M_B_CPU0_SB_RSP<1>")
	)
	(segment
		(start 320.802762 -250.74626)
		(end 316.952376 -250.74626)
		(width 0.18288)
		(layer "In6.Cu")
		(net "M_B_CPU0_SB_RSP<1>")
	)
	(segment
		(start 301.99457 -246.367554)
		(end 301.76851 -246.367554)
		(width 0.18288)
		(layer "In6.Cu")
		(net "M_B_CPU0_SB_RSP<1>")
	)
	(segment
		(start 304.992532 -246.89054)
		(end 303.907952 -246.89054)
		(width 0.18288)
		(layer "In6.Cu")
		(net "M_B_CPU0_SB_RSP<1>")
	)
	(segment
		(start 297.684444 -243.64442)
		(end 297.555666 -243.773198)
		(width 0.18288)
		(layer "In6.Cu")
		(net "M_B_CPU0_SB_RSP<1>")
	)
	(segment
		(start 306.005992 -246.89054)
		(end 305.845972 -246.73052)
		(width 0.18288)
		(layer "In6.Cu")
		(net "M_B_CPU0_SB_RSP<1>")
	)
	(segment
		(start 303.907952 -246.89054)
		(end 302.956722 -245.93931)
		(width 0.18288)
		(layer "In6.Cu")
		(net "M_B_CPU0_SB_RSP<1>")
	)
	(segment
		(start 347.942916 -254.197612)
		(end 347.942916 -254.733298)
		(width 0.20066)
		(layer "F.Cu")
		(net "M_B_CPU0_SB_RSP<0>")
	)
	(segment
		(start 347.942916 -254.733298)
		(end 347.942662 -254.733552)
		(width 0.20066)
		(layer "F.Cu")
		(net "M_B_CPU0_SB_RSP<0>")
	)
	(segment
		(start 287.360614 -243.216684)
		(end 286.255714 -243.216684)
		(width 0.20066)
		(layer "F.Cu")
		(net "M_B_CPU0_SB_RSP<0>")
	)
	(segment
		(start 295.275254 -245.340886)
		(end 294.640762 -245.340886)
		(width 0.18288)
		(layer "In6.Cu")
		(net "M_B_CPU0_SB_RSP<0>")
	)
	(segment
		(start 302.613314 -248.88825)
		(end 301.534322 -248.574814)
		(width 0.18288)
		(layer "In6.Cu")
		(net "M_B_CPU0_SB_RSP<0>")
	)
	(segment
		(start 347.942662 -254.733552)
		(end 347.451934 -254.512826)
		(width 0.088646)
		(layer "In6.Cu")
		(net "M_B_CPU0_SB_RSP<0>")
	)
	(segment
		(start 290.463732 -244.491002)
		(end 290.268152 -244.686582)
		(width 0.18288)
		(layer "In6.Cu")
		(net "M_B_CPU0_SB_RSP<0>")
	)
	(segment
		(start 346.158312 -253.399544)
		(end 345.971876 -253.213108)
		(width 0.088646)
		(layer "In6.Cu")
		(net "M_B_CPU0_SB_RSP<0>")
	)
	(segment
		(start 294.44442 -245.144544)
		(end 292.866318 -244.491002)
		(width 0.18288)
		(layer "In6.Cu")
		(net "M_B_CPU0_SB_RSP<0>")
	)
	(segment
		(start 345.652598 -251.983494)
		(end 335.972912 -251.983494)
		(width 0.18288)
		(layer "In6.Cu")
		(net "M_B_CPU0_SB_RSP<0>")
	)
	(segment
		(start 323.965824 -248.991628)
		(end 321.034156 -251.923296)
		(width 0.18288)
		(layer "In6.Cu")
		(net "M_B_CPU0_SB_RSP<0>")
	)
	(segment
		(start 329.699874 -251.597668)
		(end 327.093834 -248.991628)
		(width 0.18288)
		(layer "In6.Cu")
		(net "M_B_CPU0_SB_RSP<0>")
	)
	(segment
		(start 304.406554 -249.649234)
		(end 304.016664 -249.594878)
		(width 0.18288)
		(layer "In6.Cu")
		(net "M_B_CPU0_SB_RSP<0>")
	)
	(segment
		(start 292.866318 -244.491002)
		(end 290.463732 -244.491002)
		(width 0.18288)
		(layer "In6.Cu")
		(net "M_B_CPU0_SB_RSP<0>")
	)
	(segment
		(start 314.403994 -250.481592)
		(end 312.55462 -249.715782)
		(width 0.18288)
		(layer "In6.Cu")
		(net "M_B_CPU0_SB_RSP<0>")
	)
	(segment
		(start 310.94553 -249.715782)
		(end 310.043576 -250.617736)
		(width 0.18288)
		(layer "In6.Cu")
		(net "M_B_CPU0_SB_RSP<0>")
	)
	(segment
		(start 346.158312 -253.919736)
		(end 346.158312 -253.399544)
		(width 0.088646)
		(layer "In6.Cu")
		(net "M_B_CPU0_SB_RSP<0>")
	)
	(segment
		(start 327.093834 -248.991628)
		(end 323.965824 -248.991628)
		(width 0.18288)
		(layer "In6.Cu")
		(net "M_B_CPU0_SB_RSP<0>")
	)
	(segment
		(start 321.034156 -251.923296)
		(end 316.70625 -251.923296)
		(width 0.18288)
		(layer "In6.Cu")
		(net "M_B_CPU0_SB_RSP<0>")
	)
	(segment
		(start 345.971876 -252.302772)
		(end 345.652598 -251.983494)
		(width 0.18288)
		(layer "In6.Cu")
		(net "M_B_CPU0_SB_RSP<0>")
	)
	(segment
		(start 316.70625 -251.923296)
		(end 315.237622 -251.31522)
		(width 0.18288)
		(layer "In6.Cu")
		(net "M_B_CPU0_SB_RSP<0>")
	)
	(segment
		(start 299.607732 -247.040908)
		(end 298.694094 -247.040908)
		(width 0.18288)
		(layer "In6.Cu")
		(net "M_B_CPU0_SB_RSP<0>")
	)
	(segment
		(start 335.972912 -251.983494)
		(end 335.587086 -251.597668)
		(width 0.18288)
		(layer "In6.Cu")
		(net "M_B_CPU0_SB_RSP<0>")
	)
	(segment
		(start 304.016664 -249.594878)
		(end 302.613314 -248.88825)
		(width 0.18288)
		(layer "In6.Cu")
		(net "M_B_CPU0_SB_RSP<0>")
	)
	(segment
		(start 345.971876 -253.213108)
		(end 345.971876 -252.781308)
		(width 0.088646)
		(layer "In6.Cu")
		(net "M_B_CPU0_SB_RSP<0>")
	)
	(segment
		(start 297.32351 -246.43207)
		(end 296.436034 -246.192294)
		(width 0.18288)
		(layer "In6.Cu")
		(net "M_B_CPU0_SB_RSP<0>")
	)
	(segment
		(start 312.55462 -249.715782)
		(end 310.94553 -249.715782)
		(width 0.18288)
		(layer "In6.Cu")
		(net "M_B_CPU0_SB_RSP<0>")
	)
	(segment
		(start 301.534322 -248.574814)
		(end 299.607732 -247.040908)
		(width 0.18288)
		(layer "In6.Cu")
		(net "M_B_CPU0_SB_RSP<0>")
	)
	(segment
		(start 296.436034 -246.192294)
		(end 295.275254 -245.340886)
		(width 0.18288)
		(layer "In6.Cu")
		(net "M_B_CPU0_SB_RSP<0>")
	)
	(segment
		(start 315.237622 -251.31522)
		(end 314.403994 -250.481592)
		(width 0.18288)
		(layer "In6.Cu")
		(net "M_B_CPU0_SB_RSP<0>")
	)
	(segment
		(start 345.971876 -252.781308)
		(end 345.971876 -252.302772)
		(width 0.18288)
		(layer "In6.Cu")
		(net "M_B_CPU0_SB_RSP<0>")
	)
	(segment
		(start 346.345764 -254.244094)
		(end 346.336874 -254.239014)
		(width 0.088646)
		(layer "In6.Cu")
		(net "M_B_CPU0_SB_RSP<0>")
	)
	(segment
		(start 306.722018 -249.649234)
		(end 304.406554 -249.649234)
		(width 0.18288)
		(layer "In6.Cu")
		(net "M_B_CPU0_SB_RSP<0>")
	)
	(segment
		(start 289.456622 -244.686582)
		(end 288.38779 -244.24386)
		(width 0.18288)
		(layer "In6.Cu")
		(net "M_B_CPU0_SB_RSP<0>")
	)
	(segment
		(start 294.640762 -245.340886)
		(end 294.44442 -245.144544)
		(width 0.18288)
		(layer "In6.Cu")
		(net "M_B_CPU0_SB_RSP<0>")
	)
	(segment
		(start 290.268152 -244.686582)
		(end 289.456622 -244.686582)
		(width 0.18288)
		(layer "In6.Cu")
		(net "M_B_CPU0_SB_RSP<0>")
	)
	(segment
		(start 298.694094 -247.040908)
		(end 297.32351 -246.43207)
		(width 0.18288)
		(layer "In6.Cu")
		(net "M_B_CPU0_SB_RSP<0>")
	)
	(segment
		(start 307.69052 -250.617736)
		(end 306.722018 -249.649234)
		(width 0.18288)
		(layer "In6.Cu")
		(net "M_B_CPU0_SB_RSP<0>")
	)
	(segment
		(start 310.043576 -250.617736)
		(end 307.69052 -250.617736)
		(width 0.18288)
		(layer "In6.Cu")
		(net "M_B_CPU0_SB_RSP<0>")
	)
	(segment
		(start 288.38779 -244.24386)
		(end 287.360614 -243.216684)
		(width 0.18288)
		(layer "In6.Cu")
		(net "M_B_CPU0_SB_RSP<0>")
	)
	(segment
		(start 335.587086 -251.597668)
		(end 329.699874 -251.597668)
		(width 0.18288)
		(layer "In6.Cu")
		(net "M_B_CPU0_SB_RSP<0>")
	)
	(arc
		(start 347.451934 -254.512826)
		(mid 347.124169 -254.313513)
		(end 346.740734 -254.302006)
		(width 0.088646)
		(layer "In6.Cu")
		(net "M_B_CPU0_SB_RSP<0>")
	)
	(arc
		(start 346.740734 -254.302006)
		(mid 346.537765 -254.310401)
		(end 346.345764 -254.244094)
		(width 0.088646)
		(layer "In6.Cu")
		(net "M_B_CPU0_SB_RSP<0>")
	)
	(arc
		(start 346.336874 -254.239014)
		(mid 346.20596 -254.102654)
		(end 346.158312 -253.919736)
		(width 0.088646)
		(layer "In6.Cu")
		(net "M_B_CPU0_SB_RSP<0>")
	)
	(segment
		(start 295.000426 -247.04167)
		(end 292.927532 -247.04167)
		(width 0.1016)
		(layer "F.Cu")
		(net "M_B_CPU0_SB_PAR")
	)
	(segment
		(start 299.004482 -246.616728)
		(end 297.899582 -246.616728)
		(width 0.20066)
		(layer "F.Cu")
		(net "M_B_CPU0_SB_PAR")
	)
	(segment
		(start 296.42943 -246.824246)
		(end 296.217594 -246.61241)
		(width 0.20066)
		(layer "F.Cu")
		(net "M_B_CPU0_SB_PAR")
	)
	(segment
		(start 292.178994 -246.9134)
		(end 292.178994 -246.742712)
		(width 0.20066)
		(layer "F.Cu")
		(net "M_B_CPU0_SB_PAR")
	)
	(segment
		(start 338.90458 -247.714262)
		(end 338.90458 -247.178576)
		(width 0.20066)
		(layer "F.Cu")
		(net "M_B_CPU0_SB_PAR")
	)
	(segment
		(start 338.90458 -247.178576)
		(end 338.904834 -247.178322)
		(width 0.20066)
		(layer "F.Cu")
		(net "M_B_CPU0_SB_PAR")
	)
	(segment
		(start 297.899582 -246.616728)
		(end 297.08348 -246.616728)
		(width 0.20066)
		(layer "F.Cu")
		(net "M_B_CPU0_SB_PAR")
	)
	(segment
		(start 292.178994 -246.742712)
		(end 292.05301 -246.616728)
		(width 0.20066)
		(layer "F.Cu")
		(net "M_B_CPU0_SB_PAR")
	)
	(segment
		(start 292.689534 -247.04167)
		(end 292.67531 -247.055894)
		(width 0.101854)
		(layer "F.Cu")
		(net "M_B_CPU0_SB_PAR")
	)
	(segment
		(start 295.82237 -246.61241)
		(end 295.693846 -246.740934)
		(width 0.20066)
		(layer "F.Cu")
		(net "M_B_CPU0_SB_PAR")
	)
	(segment
		(start 296.217594 -246.61241)
		(end 295.82237 -246.61241)
		(width 0.20066)
		(layer "F.Cu")
		(net "M_B_CPU0_SB_PAR")
	)
	(segment
		(start 297.08348 -246.616728)
		(end 296.875962 -246.824246)
		(width 0.20066)
		(layer "F.Cu")
		(net "M_B_CPU0_SB_PAR")
	)
	(segment
		(start 295.693846 -246.892572)
		(end 295.544748 -247.04167)
		(width 0.20066)
		(layer "F.Cu")
		(net "M_B_CPU0_SB_PAR")
	)
	(segment
		(start 296.875962 -246.824246)
		(end 296.42943 -246.824246)
		(width 0.20066)
		(layer "F.Cu")
		(net "M_B_CPU0_SB_PAR")
	)
	(segment
		(start 292.927532 -247.04167)
		(end 292.689534 -247.04167)
		(width 0.101854)
		(layer "F.Cu")
		(net "M_B_CPU0_SB_PAR")
	)
	(segment
		(start 295.693846 -246.740934)
		(end 295.693846 -246.892572)
		(width 0.20066)
		(layer "F.Cu")
		(net "M_B_CPU0_SB_PAR")
	)
	(segment
		(start 292.05301 -246.616728)
		(end 290.355782 -246.616728)
		(width 0.20066)
		(layer "F.Cu")
		(net "M_B_CPU0_SB_PAR")
	)
	(segment
		(start 292.321488 -247.055894)
		(end 292.178994 -246.9134)
		(width 0.20066)
		(layer "F.Cu")
		(net "M_B_CPU0_SB_PAR")
	)
	(segment
		(start 292.67531 -247.055894)
		(end 292.321488 -247.055894)
		(width 0.20066)
		(layer "F.Cu")
		(net "M_B_CPU0_SB_PAR")
	)
	(segment
		(start 295.544748 -247.04167)
		(end 295.000426 -247.04167)
		(width 0.20066)
		(layer "F.Cu")
		(net "M_B_CPU0_SB_PAR")
	)
	(segment
		(start 310.844946 -246.419878)
		(end 310.148224 -247.1166)
		(width 0.18288)
		(layer "In2.Cu")
		(net "M_B_CPU0_SB_PAR")
	)
	(segment
		(start 317.674752 -247.40108)
		(end 317.361316 -247.40108)
		(width 0.18288)
		(layer "In2.Cu")
		(net "M_B_CPU0_SB_PAR")
	)
	(segment
		(start 310.148224 -247.1166)
		(end 309.875174 -247.1166)
		(width 0.18288)
		(layer "In2.Cu")
		(net "M_B_CPU0_SB_PAR")
	)
	(segment
		(start 331.856334 -246.73941)
		(end 331.649832 -246.73941)
		(width 0.088646)
		(layer "In2.Cu")
		(net "M_B_CPU0_SB_PAR")
	)
	(segment
		(start 318.060832 -246.360696)
		(end 317.867792 -246.553736)
		(width 0.18288)
		(layer "In2.Cu")
		(net "M_B_CPU0_SB_PAR")
	)
	(segment
		(start 301.877222 -246.660924)
		(end 300.832266 -246.660924)
		(width 0.18288)
		(layer "In2.Cu")
		(net "M_B_CPU0_SB_PAR")
	)
	(segment
		(start 337.307682 -246.688864)
		(end 337.29295 -246.680228)
		(width 0.088646)
		(layer "In2.Cu")
		(net "M_B_CPU0_SB_PAR")
	)
	(segment
		(start 315.043312 -246.553736)
		(end 315.043312 -247.118124)
		(width 0.18288)
		(layer "In2.Cu")
		(net "M_B_CPU0_SB_PAR")
	)
	(segment
		(start 318.773556 -247.40108)
		(end 318.573912 -247.201436)
		(width 0.18288)
		(layer "In2.Cu")
		(net "M_B_CPU0_SB_PAR")
	)
	(segment
		(start 300.832266 -246.660924)
		(end 300.439328 -247.053862)
		(width 0.18288)
		(layer "In2.Cu")
		(net "M_B_CPU0_SB_PAR")
	)
	(segment
		(start 314.577222 -247.311164)
		(end 314.30214 -247.036082)
		(width 0.18288)
		(layer "In2.Cu")
		(net "M_B_CPU0_SB_PAR")
	)
	(segment
		(start 331.475588 -246.565166)
		(end 331.080618 -246.565166)
		(width 0.088646)
		(layer "In2.Cu")
		(net "M_B_CPU0_SB_PAR")
	)
	(segment
		(start 316.455552 -246.557038)
		(end 316.455552 -247.20804)
		(width 0.18288)
		(layer "In2.Cu")
		(net "M_B_CPU0_SB_PAR")
	)
	(segment
		(start 309.875174 -247.1166)
		(end 309.810658 -247.052084)
		(width 0.18288)
		(layer "In2.Cu")
		(net "M_B_CPU0_SB_PAR")
	)
	(segment
		(start 311.11825 -246.419878)
		(end 310.844946 -246.419878)
		(width 0.18288)
		(layer "In2.Cu")
		(net "M_B_CPU0_SB_PAR")
	)
	(segment
		(start 338.904834 -247.178322)
		(end 338.276692 -246.705628)
		(width 0.088646)
		(layer "In2.Cu")
		(net "M_B_CPU0_SB_PAR")
	)
	(segment
		(start 317.361316 -247.40108)
		(end 317.161672 -247.201436)
		(width 0.18288)
		(layer "In2.Cu")
		(net "M_B_CPU0_SB_PAR")
	)
	(segment
		(start 306.432966 -246.889524)
		(end 305.939952 -247.382538)
		(width 0.18288)
		(layer "In2.Cu")
		(net "M_B_CPU0_SB_PAR")
	)
	(segment
		(start 316.262512 -247.40108)
		(end 315.949076 -247.40108)
		(width 0.18288)
		(layer "In2.Cu")
		(net "M_B_CPU0_SB_PAR")
	)
	(segment
		(start 315.949076 -247.40108)
		(end 315.749432 -247.201436)
		(width 0.18288)
		(layer "In2.Cu")
		(net "M_B_CPU0_SB_PAR")
	)
	(segment
		(start 318.380872 -246.360696)
		(end 318.060832 -246.360696)
		(width 0.18288)
		(layer "In2.Cu")
		(net "M_B_CPU0_SB_PAR")
	)
	(segment
		(start 316.648592 -246.363998)
		(end 316.455552 -246.557038)
		(width 0.18288)
		(layer "In2.Cu")
		(net "M_B_CPU0_SB_PAR")
	)
	(segment
		(start 331.649832 -246.73941)
		(end 331.475588 -246.565166)
		(width 0.088646)
		(layer "In2.Cu")
		(net "M_B_CPU0_SB_PAR")
	)
	(segment
		(start 305.939952 -247.382538)
		(end 304.869088 -247.382538)
		(width 0.18288)
		(layer "In2.Cu")
		(net "M_B_CPU0_SB_PAR")
	)
	(segment
		(start 317.867792 -247.20804)
		(end 317.674752 -247.40108)
		(width 0.18288)
		(layer "In2.Cu")
		(net "M_B_CPU0_SB_PAR")
	)
	(segment
		(start 303.313846 -246.759476)
		(end 303.01946 -247.053862)
		(width 0.18288)
		(layer "In2.Cu")
		(net "M_B_CPU0_SB_PAR")
	)
	(segment
		(start 300.069758 -247.053862)
		(end 299.632624 -246.616728)
		(width 0.18288)
		(layer "In2.Cu")
		(net "M_B_CPU0_SB_PAR")
	)
	(segment
		(start 306.813458 -246.889524)
		(end 306.432966 -246.889524)
		(width 0.18288)
		(layer "In2.Cu")
		(net "M_B_CPU0_SB_PAR")
	)
	(segment
		(start 315.556392 -246.360696)
		(end 315.236352 -246.360696)
		(width 0.18288)
		(layer "In2.Cu")
		(net "M_B_CPU0_SB_PAR")
	)
	(segment
		(start 317.161672 -247.201436)
		(end 317.161672 -246.557038)
		(width 0.18288)
		(layer "In2.Cu")
		(net "M_B_CPU0_SB_PAR")
	)
	(segment
		(start 314.850272 -247.311164)
		(end 314.577222 -247.311164)
		(width 0.18288)
		(layer "In2.Cu")
		(net "M_B_CPU0_SB_PAR")
	)
	(segment
		(start 315.236352 -246.360696)
		(end 315.043312 -246.553736)
		(width 0.18288)
		(layer "In2.Cu")
		(net "M_B_CPU0_SB_PAR")
	)
	(segment
		(start 321.304412 -247.40108)
		(end 318.773556 -247.40108)
		(width 0.18288)
		(layer "In2.Cu")
		(net "M_B_CPU0_SB_PAR")
	)
	(segment
		(start 331.080618 -246.565166)
		(end 322.140326 -246.565166)
		(width 0.18288)
		(layer "In2.Cu")
		(net "M_B_CPU0_SB_PAR")
	)
	(segment
		(start 315.749432 -247.201436)
		(end 315.749432 -246.553736)
		(width 0.18288)
		(layer "In2.Cu")
		(net "M_B_CPU0_SB_PAR")
	)
	(segment
		(start 309.810658 -247.052084)
		(end 307.96992 -247.052084)
		(width 0.18288)
		(layer "In2.Cu")
		(net "M_B_CPU0_SB_PAR")
	)
	(segment
		(start 318.573912 -246.553736)
		(end 318.380872 -246.360696)
		(width 0.18288)
		(layer "In2.Cu")
		(net "M_B_CPU0_SB_PAR")
	)
	(segment
		(start 307.96992 -247.052084)
		(end 307.804058 -247.217946)
		(width 0.18288)
		(layer "In2.Cu")
		(net "M_B_CPU0_SB_PAR")
	)
	(segment
		(start 317.161672 -246.557038)
		(end 316.968632 -246.363998)
		(width 0.18288)
		(layer "In2.Cu")
		(net "M_B_CPU0_SB_PAR")
	)
	(segment
		(start 315.043312 -247.118124)
		(end 314.850272 -247.311164)
		(width 0.18288)
		(layer "In2.Cu")
		(net "M_B_CPU0_SB_PAR")
	)
	(segment
		(start 317.867792 -246.553736)
		(end 317.867792 -247.20804)
		(width 0.18288)
		(layer "In2.Cu")
		(net "M_B_CPU0_SB_PAR")
	)
	(segment
		(start 338.276692 -246.705628)
		(end 338.247482 -246.688864)
		(width 0.088646)
		(layer "In2.Cu")
		(net "M_B_CPU0_SB_PAR")
	)
	(segment
		(start 311.734454 -247.036082)
		(end 311.11825 -246.419878)
		(width 0.18288)
		(layer "In2.Cu")
		(net "M_B_CPU0_SB_PAR")
	)
	(segment
		(start 303.01946 -247.053862)
		(end 302.27016 -247.053862)
		(width 0.18288)
		(layer "In2.Cu")
		(net "M_B_CPU0_SB_PAR")
	)
	(segment
		(start 316.968632 -246.363998)
		(end 316.648592 -246.363998)
		(width 0.18288)
		(layer "In2.Cu")
		(net "M_B_CPU0_SB_PAR")
	)
	(segment
		(start 336.367882 -246.688864)
		(end 336.357468 -246.682768)
		(width 0.088646)
		(layer "In2.Cu")
		(net "M_B_CPU0_SB_PAR")
	)
	(segment
		(start 307.14188 -247.217946)
		(end 306.813458 -246.889524)
		(width 0.18288)
		(layer "In2.Cu")
		(net "M_B_CPU0_SB_PAR")
	)
	(segment
		(start 316.455552 -247.20804)
		(end 316.262512 -247.40108)
		(width 0.18288)
		(layer "In2.Cu")
		(net "M_B_CPU0_SB_PAR")
	)
	(segment
		(start 322.140326 -246.565166)
		(end 321.304412 -247.40108)
		(width 0.18288)
		(layer "In2.Cu")
		(net "M_B_CPU0_SB_PAR")
	)
	(segment
		(start 300.439328 -247.053862)
		(end 300.069758 -247.053862)
		(width 0.18288)
		(layer "In2.Cu")
		(net "M_B_CPU0_SB_PAR")
	)
	(segment
		(start 318.573912 -247.201436)
		(end 318.573912 -246.553736)
		(width 0.18288)
		(layer "In2.Cu")
		(net "M_B_CPU0_SB_PAR")
	)
	(segment
		(start 307.804058 -247.217946)
		(end 307.14188 -247.217946)
		(width 0.18288)
		(layer "In2.Cu")
		(net "M_B_CPU0_SB_PAR")
	)
	(segment
		(start 299.632624 -246.616728)
		(end 299.004482 -246.616728)
		(width 0.18288)
		(layer "In2.Cu")
		(net "M_B_CPU0_SB_PAR")
	)
	(segment
		(start 304.246026 -246.759476)
		(end 303.313846 -246.759476)
		(width 0.18288)
		(layer "In2.Cu")
		(net "M_B_CPU0_SB_PAR")
	)
	(segment
		(start 302.27016 -247.053862)
		(end 301.877222 -246.660924)
		(width 0.18288)
		(layer "In2.Cu")
		(net "M_B_CPU0_SB_PAR")
	)
	(segment
		(start 315.749432 -246.553736)
		(end 315.556392 -246.360696)
		(width 0.18288)
		(layer "In2.Cu")
		(net "M_B_CPU0_SB_PAR")
	)
	(segment
		(start 304.869088 -247.382538)
		(end 304.246026 -246.759476)
		(width 0.18288)
		(layer "In2.Cu")
		(net "M_B_CPU0_SB_PAR")
	)
	(segment
		(start 314.30214 -247.036082)
		(end 311.734454 -247.036082)
		(width 0.18288)
		(layer "In2.Cu")
		(net "M_B_CPU0_SB_PAR")
	)
	(arc
		(start 333.923132 -246.688864)
		(mid 333.735934 -246.739007)
		(end 333.548736 -246.688864)
		(width 0.088646)
		(layer "In2.Cu")
		(net "M_B_CPU0_SB_PAR")
	)
	(arc
		(start 338.247482 -246.688864)
		(mid 337.96478 -246.613122)
		(end 337.682078 -246.688864)
		(width 0.088646)
		(layer "In2.Cu")
		(net "M_B_CPU0_SB_PAR")
	)
	(arc
		(start 336.742278 -246.688864)
		(mid 336.55508 -246.739007)
		(end 336.367882 -246.688864)
		(width 0.088646)
		(layer "In2.Cu")
		(net "M_B_CPU0_SB_PAR")
	)
	(arc
		(start 332.608936 -246.688864)
		(mid 332.326234 -246.613088)
		(end 332.043532 -246.688864)
		(width 0.088646)
		(layer "In2.Cu")
		(net "M_B_CPU0_SB_PAR")
	)
	(arc
		(start 337.29295 -246.680228)
		(mid 337.016475 -246.612908)
		(end 336.742278 -246.688864)
		(width 0.088646)
		(layer "In2.Cu")
		(net "M_B_CPU0_SB_PAR")
	)
	(arc
		(start 333.548736 -246.688864)
		(mid 333.266034 -246.613088)
		(end 332.983332 -246.688864)
		(width 0.088646)
		(layer "In2.Cu")
		(net "M_B_CPU0_SB_PAR")
	)
	(arc
		(start 337.682078 -246.688864)
		(mid 337.49488 -246.739007)
		(end 337.307682 -246.688864)
		(width 0.088646)
		(layer "In2.Cu")
		(net "M_B_CPU0_SB_PAR")
	)
	(arc
		(start 334.862932 -246.688864)
		(mid 334.675734 -246.739007)
		(end 334.488536 -246.688864)
		(width 0.088646)
		(layer "In2.Cu")
		(net "M_B_CPU0_SB_PAR")
	)
	(arc
		(start 335.802732 -246.688864)
		(mid 335.615534 -246.739007)
		(end 335.428336 -246.688864)
		(width 0.088646)
		(layer "In2.Cu")
		(net "M_B_CPU0_SB_PAR")
	)
	(arc
		(start 332.043532 -246.688864)
		(mid 331.95326 -246.726463)
		(end 331.856334 -246.73941)
		(width 0.088646)
		(layer "In2.Cu")
		(net "M_B_CPU0_SB_PAR")
	)
	(arc
		(start 334.488536 -246.688864)
		(mid 334.205834 -246.613088)
		(end 333.923132 -246.688864)
		(width 0.088646)
		(layer "In2.Cu")
		(net "M_B_CPU0_SB_PAR")
	)
	(arc
		(start 335.428336 -246.688864)
		(mid 335.145634 -246.613088)
		(end 334.862932 -246.688864)
		(width 0.088646)
		(layer "In2.Cu")
		(net "M_B_CPU0_SB_PAR")
	)
	(arc
		(start 332.983332 -246.688864)
		(mid 332.796134 -246.739007)
		(end 332.608936 -246.688864)
		(width 0.088646)
		(layer "In2.Cu")
		(net "M_B_CPU0_SB_PAR")
	)
	(arc
		(start 336.357468 -246.682768)
		(mid 336.07929 -246.613045)
		(end 335.802732 -246.688864)
		(width 0.088646)
		(layer "In2.Cu")
		(net "M_B_CPU0_SB_PAR")
	)
	(segment
		(start 336.085434 -242.295172)
		(end 336.085688 -242.294918)
		(width 0.20066)
		(layer "F.Cu")
		(net "M_B_CPU0_SB_DQS_DP<9>")
	)
	(segment
		(start 289.233356 -238.549434)
		(end 289.231832 -238.549434)
		(width 0.101854)
		(layer "F.Cu")
		(net "M_B_CPU0_SB_DQS_DP<9>")
	)
	(segment
		(start 288.742882 -238.280702)
		(end 288.115756 -238.280702)
		(width 0.20066)
		(layer "F.Cu")
		(net "M_B_CPU0_SB_DQS_DP<9>")
	)
	(segment
		(start 287.054798 -237.855506)
		(end 286.793686 -238.116618)
		(width 0.20066)
		(layer "F.Cu")
		(net "M_B_CPU0_SB_DQS_DP<9>")
	)
	(segment
		(start 292.989762 -237.855506)
		(end 292.72103 -237.855506)
		(width 0.20066)
		(layer "F.Cu")
		(net "M_B_CPU0_SB_DQS_DP<9>")
	)
	(segment
		(start 291.70884 -238.541814)
		(end 291.556948 -238.541814)
		(width 0.20066)
		(layer "F.Cu")
		(net "M_B_CPU0_SB_DQS_DP<9>")
	)
	(segment
		(start 289.011614 -238.549434)
		(end 288.742882 -238.280702)
		(width 0.20066)
		(layer "F.Cu")
		(net "M_B_CPU0_SB_DQS_DP<9>")
	)
	(segment
		(start 287.47974 -237.855506)
		(end 287.054798 -237.855506)
		(width 0.20066)
		(layer "F.Cu")
		(net "M_B_CPU0_SB_DQS_DP<9>")
	)
	(segment
		(start 292.295834 -238.280702)
		(end 291.969952 -238.280702)
		(width 0.20066)
		(layer "F.Cu")
		(net "M_B_CPU0_SB_DQS_DP<9>")
	)
	(segment
		(start 291.556948 -238.541814)
		(end 291.233352 -238.541814)
		(width 0.101854)
		(layer "F.Cu")
		(net "M_B_CPU0_SB_DQS_DP<9>")
	)
	(segment
		(start 288.115756 -238.280702)
		(end 287.47974 -237.855506)
		(width 0.20066)
		(layer "F.Cu")
		(net "M_B_CPU0_SB_DQS_DP<9>")
	)
	(segment
		(start 289.231832 -238.549434)
		(end 289.011614 -238.549434)
		(width 0.20066)
		(layer "F.Cu")
		(net "M_B_CPU0_SB_DQS_DP<9>")
	)
	(segment
		(start 291.233352 -238.541814)
		(end 289.477958 -238.541814)
		(width 0.1016)
		(layer "F.Cu")
		(net "M_B_CPU0_SB_DQS_DP<9>")
	)
	(segment
		(start 293.799514 -238.116618)
		(end 293.250874 -238.116618)
		(width 0.20066)
		(layer "F.Cu")
		(net "M_B_CPU0_SB_DQS_DP<9>")
	)
	(segment
		(start 293.250874 -238.116618)
		(end 292.989762 -237.855506)
		(width 0.20066)
		(layer "F.Cu")
		(net "M_B_CPU0_SB_DQS_DP<9>")
	)
	(segment
		(start 286.793686 -238.116618)
		(end 286.255714 -238.116618)
		(width 0.20066)
		(layer "F.Cu")
		(net "M_B_CPU0_SB_DQS_DP<9>")
	)
	(segment
		(start 289.477958 -238.541814)
		(end 289.240976 -238.541814)
		(width 0.101854)
		(layer "F.Cu")
		(net "M_B_CPU0_SB_DQS_DP<9>")
	)
	(segment
		(start 336.085434 -242.830858)
		(end 336.085434 -242.295172)
		(width 0.20066)
		(layer "F.Cu")
		(net "M_B_CPU0_SB_DQS_DP<9>")
	)
	(segment
		(start 291.969952 -238.280702)
		(end 291.70884 -238.541814)
		(width 0.20066)
		(layer "F.Cu")
		(net "M_B_CPU0_SB_DQS_DP<9>")
	)
	(segment
		(start 289.240976 -238.541814)
		(end 289.233356 -238.549434)
		(width 0.101854)
		(layer "F.Cu")
		(net "M_B_CPU0_SB_DQS_DP<9>")
	)
	(segment
		(start 292.72103 -237.855506)
		(end 292.295834 -238.280702)
		(width 0.20066)
		(layer "F.Cu")
		(net "M_B_CPU0_SB_DQS_DP<9>")
	)
	(segment
		(start 294.904414 -238.116618)
		(end 293.799514 -238.116618)
		(width 0.20066)
		(layer "F.Cu")
		(net "M_B_CPU0_SB_DQS_DP<9>")
	)
	(segment
		(start 307.965856 -236.847126)
		(end 307.594 -236.847126)
		(width 0.18288)
		(layer "In2.Cu")
		(net "M_B_CPU0_SB_DQS_DP<9>")
	)
	(segment
		(start 299.458888 -235.725716)
		(end 299.19295 -235.991654)
		(width 0.18288)
		(layer "In2.Cu")
		(net "M_B_CPU0_SB_DQS_DP<9>")
	)
	(segment
		(start 314.561982 -236.51845)
		(end 314.20308 -236.51845)
		(width 0.18288)
		(layer "In2.Cu")
		(net "M_B_CPU0_SB_DQS_DP<9>")
	)
	(segment
		(start 304.534316 -236.188758)
		(end 304.351944 -236.37113)
		(width 0.18288)
		(layer "In2.Cu")
		(net "M_B_CPU0_SB_DQS_DP<9>")
	)
	(segment
		(start 312.261504 -236.02823)
		(end 312.23331 -236.056424)
		(width 0.16002)
		(layer "In2.Cu")
		(net "M_B_CPU0_SB_DQS_DP<9>")
	)
	(segment
		(start 311.989216 -236.300518)
		(end 311.7469 -236.542834)
		(width 0.18288)
		(layer "In2.Cu")
		(net "M_B_CPU0_SB_DQS_DP<9>")
	)
	(segment
		(start 317.366142 -237.788196)
		(end 317.298832 -237.625382)
		(width 0.18288)
		(layer "In2.Cu")
		(net "M_B_CPU0_SB_DQS_DP<9>")
	)
	(segment
		(start 320.449448 -239.496092)
		(end 320.449448 -239.32007)
		(width 0.18288)
		(layer "In2.Cu")
		(net "M_B_CPU0_SB_DQS_DP<9>")
	)
	(segment
		(start 313.710574 -236.025944)
		(end 313.68238 -235.99775)
		(width 0.16002)
		(layer "In2.Cu")
		(net "M_B_CPU0_SB_DQS_DP<9>")
	)
	(segment
		(start 303.860708 -236.37113)
		(end 302.838104 -235.947458)
		(width 0.18288)
		(layer "In2.Cu")
		(net "M_B_CPU0_SB_DQS_DP<9>")
	)
	(segment
		(start 318.609726 -238.303816)
		(end 318.542416 -238.141002)
		(width 0.18288)
		(layer "In2.Cu")
		(net "M_B_CPU0_SB_DQS_DP<9>")
	)
	(segment
		(start 336.085688 -242.294918)
		(end 336.068162 -242.231164)
		(width 0.088646)
		(layer "In2.Cu")
		(net "M_B_CPU0_SB_DQS_DP<9>")
	)
	(segment
		(start 299.19295 -235.991654)
		(end 298.80433 -235.991654)
		(width 0.18288)
		(layer "In2.Cu")
		(net "M_B_CPU0_SB_DQS_DP<9>")
	)
	(segment
		(start 313.926474 -236.241844)
		(end 313.926474 -236.225588)
		(width 0.16002)
		(layer "In2.Cu")
		(net "M_B_CPU0_SB_DQS_DP<9>")
	)
	(segment
		(start 304.56251 -236.144308)
		(end 304.56251 -236.160564)
		(width 0.16002)
		(layer "In2.Cu")
		(net "M_B_CPU0_SB_DQS_DP<9>")
	)
	(segment
		(start 311.7469 -236.542834)
		(end 310.695848 -236.542834)
		(width 0.18288)
		(layer "In2.Cu")
		(net "M_B_CPU0_SB_DQS_DP<9>")
	)
	(segment
		(start 306.21351 -236.056424)
		(end 306.197254 -236.056424)
		(width 0.16002)
		(layer "In2.Cu")
		(net "M_B_CPU0_SB_DQS_DP<9>")
	)
	(segment
		(start 317.873126 -237.998254)
		(end 317.366142 -237.788196)
		(width 0.18288)
		(layer "In2.Cu")
		(net "M_B_CPU0_SB_DQS_DP<9>")
	)
	(segment
		(start 307.290724 -236.54385)
		(end 306.68468 -236.54385)
		(width 0.18288)
		(layer "In2.Cu")
		(net "M_B_CPU0_SB_DQS_DP<9>")
	)
	(segment
		(start 335.885536 -242.090702)
		(end 335.621884 -242.090702)
		(width 0.088646)
		(layer "In2.Cu")
		(net "M_B_CPU0_SB_DQS_DP<9>")
	)
	(segment
		(start 300.573186 -235.20654)
		(end 300.373542 -235.406184)
		(width 0.16002)
		(layer "In2.Cu")
		(net "M_B_CPU0_SB_DQS_DP<9>")
	)
	(segment
		(start 317.298832 -237.625382)
		(end 316.792102 -237.415324)
		(width 0.18288)
		(layer "In2.Cu")
		(net "M_B_CPU0_SB_DQS_DP<9>")
	)
	(segment
		(start 297.27017 -235.916724)
		(end 297.253914 -235.916724)
		(width 0.16002)
		(layer "In2.Cu")
		(net "M_B_CPU0_SB_DQS_DP<9>")
	)
	(segment
		(start 320.449448 -239.32007)
		(end 319.786 -238.656622)
		(width 0.18288)
		(layer "In2.Cu")
		(net "M_B_CPU0_SB_DQS_DP<9>")
	)
	(segment
		(start 306.413154 -236.272324)
		(end 306.413154 -236.256068)
		(width 0.16002)
		(layer "In2.Cu")
		(net "M_B_CPU0_SB_DQS_DP<9>")
	)
	(segment
		(start 294.904414 -238.01197)
		(end 294.904414 -238.116618)
		(width 0.18288)
		(layer "In2.Cu")
		(net "M_B_CPU0_SB_DQS_DP<9>")
	)
	(segment
		(start 305.93792 -235.79709)
		(end 304.925984 -235.79709)
		(width 0.18288)
		(layer "In2.Cu")
		(net "M_B_CPU0_SB_DQS_DP<9>")
	)
	(segment
		(start 321.789552 -240.836196)
		(end 321.40144 -240.448084)
		(width 0.18288)
		(layer "In2.Cu")
		(net "M_B_CPU0_SB_DQS_DP<9>")
	)
	(segment
		(start 310.0197 -236.847126)
		(end 309.715408 -236.542834)
		(width 0.18288)
		(layer "In2.Cu")
		(net "M_B_CPU0_SB_DQS_DP<9>")
	)
	(segment
		(start 319.11671 -238.513874)
		(end 318.609726 -238.303816)
		(width 0.18288)
		(layer "In2.Cu")
		(net "M_B_CPU0_SB_DQS_DP<9>")
	)
	(segment
		(start 304.806604 -235.91647)
		(end 304.77841 -235.944664)
		(width 0.16002)
		(layer "In2.Cu")
		(net "M_B_CPU0_SB_DQS_DP<9>")
	)
	(segment
		(start 304.56251 -236.160564)
		(end 304.534316 -236.188758)
		(width 0.16002)
		(layer "In2.Cu")
		(net "M_B_CPU0_SB_DQS_DP<9>")
	)
	(segment
		(start 333.078582 -241.97056)
		(end 333.068168 -241.976656)
		(width 0.088646)
		(layer "In2.Cu")
		(net "M_B_CPU0_SB_DQS_DP<9>")
	)
	(segment
		(start 306.68468 -236.54385)
		(end 306.441348 -236.300518)
		(width 0.18288)
		(layer "In2.Cu")
		(net "M_B_CPU0_SB_DQS_DP<9>")
	)
	(segment
		(start 308.270148 -236.542834)
		(end 307.965856 -236.847126)
		(width 0.18288)
		(layer "In2.Cu")
		(net "M_B_CPU0_SB_DQS_DP<9>")
	)
	(segment
		(start 313.72683 -236.025944)
		(end 313.710574 -236.025944)
		(width 0.16002)
		(layer "In2.Cu")
		(net "M_B_CPU0_SB_DQS_DP<9>")
	)
	(segment
		(start 306.413154 -236.256068)
		(end 306.21351 -236.056424)
		(width 0.16002)
		(layer "In2.Cu")
		(net "M_B_CPU0_SB_DQS_DP<9>")
	)
	(segment
		(start 316.122558 -237.272576)
		(end 316.055248 -237.109762)
		(width 0.18288)
		(layer "In2.Cu")
		(net "M_B_CPU0_SB_DQS_DP<9>")
	)
	(segment
		(start 310.391556 -236.847126)
		(end 310.0197 -236.847126)
		(width 0.18288)
		(layer "In2.Cu")
		(net "M_B_CPU0_SB_DQS_DP<9>")
	)
	(segment
		(start 313.621674 -235.937044)
		(end 312.35269 -235.937044)
		(width 0.18288)
		(layer "In2.Cu")
		(net "M_B_CPU0_SB_DQS_DP<9>")
	)
	(segment
		(start 321.013582 -239.884204)
		(end 320.83756 -239.884204)
		(width 0.18288)
		(layer "In2.Cu")
		(net "M_B_CPU0_SB_DQS_DP<9>")
	)
	(segment
		(start 307.594 -236.847126)
		(end 307.290724 -236.54385)
		(width 0.18288)
		(layer "In2.Cu")
		(net "M_B_CPU0_SB_DQS_DP<9>")
	)
	(segment
		(start 323.305424 -242.176046)
		(end 322.917566 -241.788188)
		(width 0.18288)
		(layer "In2.Cu")
		(net "M_B_CPU0_SB_DQS_DP<9>")
	)
	(segment
		(start 322.917566 -241.788188)
		(end 322.741544 -241.788188)
		(width 0.18288)
		(layer "In2.Cu")
		(net "M_B_CPU0_SB_DQS_DP<9>")
	)
	(segment
		(start 302.068992 -235.178346)
		(end 301.995078 -235.104432)
		(width 0.18288)
		(layer "In2.Cu")
		(net "M_B_CPU0_SB_DQS_DP<9>")
	)
	(segment
		(start 304.77841 -235.944664)
		(end 304.762154 -235.944664)
		(width 0.16002)
		(layer "In2.Cu")
		(net "M_B_CPU0_SB_DQS_DP<9>")
	)
	(segment
		(start 300.373542 -235.406184)
		(end 300.373542 -235.42244)
		(width 0.16002)
		(layer "In2.Cu")
		(net "M_B_CPU0_SB_DQS_DP<9>")
	)
	(segment
		(start 296.520362 -237.152942)
		(end 296.13225 -237.541054)
		(width 0.18288)
		(layer "In2.Cu")
		(net "M_B_CPU0_SB_DQS_DP<9>")
	)
	(segment
		(start 296.84726 -236.650022)
		(end 296.520362 -236.97692)
		(width 0.18288)
		(layer "In2.Cu")
		(net "M_B_CPU0_SB_DQS_DP<9>")
	)
	(segment
		(start 304.925984 -235.79709)
		(end 304.806604 -235.91647)
		(width 0.18288)
		(layer "In2.Cu")
		(net "M_B_CPU0_SB_DQS_DP<9>")
	)
	(segment
		(start 312.217054 -236.056424)
		(end 312.01741 -236.256068)
		(width 0.16002)
		(layer "In2.Cu")
		(net "M_B_CPU0_SB_DQS_DP<9>")
	)
	(segment
		(start 319.27927 -238.446564)
		(end 319.11671 -238.513874)
		(width 0.18288)
		(layer "In2.Cu")
		(net "M_B_CPU0_SB_DQS_DP<9>")
	)
	(segment
		(start 335.383886 -242.005358)
		(end 335.362804 -241.988086)
		(width 0.088646)
		(layer "In2.Cu")
		(net "M_B_CPU0_SB_DQS_DP<9>")
	)
	(segment
		(start 312.23331 -236.056424)
		(end 312.217054 -236.056424)
		(width 0.16002)
		(layer "In2.Cu")
		(net "M_B_CPU0_SB_DQS_DP<9>")
	)
	(segment
		(start 297.253914 -235.916724)
		(end 297.05427 -236.116368)
		(width 0.16002)
		(layer "In2.Cu")
		(net "M_B_CPU0_SB_DQS_DP<9>")
	)
	(segment
		(start 322.741544 -241.788188)
		(end 322.353432 -241.400076)
		(width 0.18288)
		(layer "In2.Cu")
		(net "M_B_CPU0_SB_DQS_DP<9>")
	)
	(segment
		(start 334.958182 -241.97056)
		(end 334.947768 -241.976656)
		(width 0.088646)
		(layer "In2.Cu")
		(net "M_B_CPU0_SB_DQS_DP<9>")
	)
	(segment
		(start 309.715408 -236.542834)
		(end 308.270148 -236.542834)
		(width 0.18288)
		(layer "In2.Cu")
		(net "M_B_CPU0_SB_DQS_DP<9>")
	)
	(segment
		(start 312.01741 -236.256068)
		(end 312.01741 -236.272324)
		(width 0.16002)
		(layer "In2.Cu")
		(net "M_B_CPU0_SB_DQS_DP<9>")
	)
	(segment
		(start 321.40144 -240.272062)
		(end 321.013582 -239.884204)
		(width 0.18288)
		(layer "In2.Cu")
		(net "M_B_CPU0_SB_DQS_DP<9>")
	)
	(segment
		(start 296.520362 -236.97692)
		(end 296.520362 -237.152942)
		(width 0.18288)
		(layer "In2.Cu")
		(net "M_B_CPU0_SB_DQS_DP<9>")
	)
	(segment
		(start 331.896212 -242.116356)
		(end 331.063854 -242.116356)
		(width 0.088646)
		(layer "In2.Cu")
		(net "M_B_CPU0_SB_DQS_DP<9>")
	)
	(segment
		(start 312.01741 -236.272324)
		(end 311.989216 -236.300518)
		(width 0.16002)
		(layer "In2.Cu")
		(net "M_B_CPU0_SB_DQS_DP<9>")
	)
	(segment
		(start 312.35269 -235.937044)
		(end 312.261504 -236.02823)
		(width 0.18288)
		(layer "In2.Cu")
		(net "M_B_CPU0_SB_DQS_DP<9>")
	)
	(segment
		(start 297.05427 -236.116368)
		(end 297.05427 -236.132624)
		(width 0.16002)
		(layer "In2.Cu")
		(net "M_B_CPU0_SB_DQS_DP<9>")
	)
	(segment
		(start 332.092554 -241.920014)
		(end 331.896212 -242.116356)
		(width 0.088646)
		(layer "In2.Cu")
		(net "M_B_CPU0_SB_DQS_DP<9>")
	)
	(segment
		(start 302.34128 -235.450634)
		(end 302.313086 -235.42244)
		(width 0.16002)
		(layer "In2.Cu")
		(net "M_B_CPU0_SB_DQS_DP<9>")
	)
	(segment
		(start 296.13225 -237.541054)
		(end 295.956228 -237.541054)
		(width 0.18288)
		(layer "In2.Cu")
		(net "M_B_CPU0_SB_DQS_DP<9>")
	)
	(segment
		(start 302.113442 -235.20654)
		(end 302.097186 -235.20654)
		(width 0.16002)
		(layer "In2.Cu")
		(net "M_B_CPU0_SB_DQS_DP<9>")
	)
	(segment
		(start 318.542416 -238.141002)
		(end 318.035686 -237.930944)
		(width 0.18288)
		(layer "In2.Cu")
		(net "M_B_CPU0_SB_DQS_DP<9>")
	)
	(segment
		(start 313.954668 -236.270038)
		(end 313.926474 -236.241844)
		(width 0.16002)
		(layer "In2.Cu")
		(net "M_B_CPU0_SB_DQS_DP<9>")
	)
	(segment
		(start 295.956228 -237.541054)
		(end 295.688766 -237.808516)
		(width 0.18288)
		(layer "In2.Cu")
		(net "M_B_CPU0_SB_DQS_DP<9>")
	)
	(segment
		(start 313.926474 -236.225588)
		(end 313.72683 -236.025944)
		(width 0.16002)
		(layer "In2.Cu")
		(net "M_B_CPU0_SB_DQS_DP<9>")
	)
	(segment
		(start 316.055248 -237.109762)
		(end 315.009784 -236.676438)
		(width 0.18288)
		(layer "In2.Cu")
		(net "M_B_CPU0_SB_DQS_DP<9>")
	)
	(segment
		(start 316.629542 -237.482634)
		(end 316.122558 -237.272576)
		(width 0.18288)
		(layer "In2.Cu")
		(net "M_B_CPU0_SB_DQS_DP<9>")
	)
	(segment
		(start 306.441348 -236.300518)
		(end 306.413154 -236.272324)
		(width 0.16002)
		(layer "In2.Cu")
		(net "M_B_CPU0_SB_DQS_DP<9>")
	)
	(segment
		(start 322.353432 -241.224054)
		(end 321.965574 -240.836196)
		(width 0.18288)
		(layer "In2.Cu")
		(net "M_B_CPU0_SB_DQS_DP<9>")
	)
	(segment
		(start 302.313086 -235.42244)
		(end 302.313086 -235.406184)
		(width 0.16002)
		(layer "In2.Cu")
		(net "M_B_CPU0_SB_DQS_DP<9>")
	)
	(segment
		(start 296.84726 -236.339634)
		(end 296.84726 -236.650022)
		(width 0.18288)
		(layer "In2.Cu")
		(net "M_B_CPU0_SB_DQS_DP<9>")
	)
	(segment
		(start 331.063854 -242.116356)
		(end 331.004164 -242.176046)
		(width 0.088646)
		(layer "In2.Cu")
		(net "M_B_CPU0_SB_DQS_DP<9>")
	)
	(segment
		(start 306.16906 -236.02823)
		(end 305.93792 -235.79709)
		(width 0.18288)
		(layer "In2.Cu")
		(net "M_B_CPU0_SB_DQS_DP<9>")
	)
	(segment
		(start 300.345348 -235.450634)
		(end 300.070266 -235.725716)
		(width 0.18288)
		(layer "In2.Cu")
		(net "M_B_CPU0_SB_DQS_DP<9>")
	)
	(segment
		(start 302.838104 -235.947458)
		(end 302.34128 -235.450634)
		(width 0.18288)
		(layer "In2.Cu")
		(net "M_B_CPU0_SB_DQS_DP<9>")
	)
	(segment
		(start 336.068162 -242.231164)
		(end 335.885536 -242.090702)
		(width 0.088646)
		(layer "In2.Cu")
		(net "M_B_CPU0_SB_DQS_DP<9>")
	)
	(segment
		(start 306.197254 -236.056424)
		(end 306.16906 -236.02823)
		(width 0.16002)
		(layer "In2.Cu")
		(net "M_B_CPU0_SB_DQS_DP<9>")
	)
	(segment
		(start 300.617636 -235.178346)
		(end 300.589442 -235.20654)
		(width 0.16002)
		(layer "In2.Cu")
		(net "M_B_CPU0_SB_DQS_DP<9>")
	)
	(segment
		(start 313.68238 -235.99775)
		(end 313.621674 -235.937044)
		(width 0.18288)
		(layer "In2.Cu")
		(net "M_B_CPU0_SB_DQS_DP<9>")
	)
	(segment
		(start 300.589442 -235.20654)
		(end 300.573186 -235.20654)
		(width 0.16002)
		(layer "In2.Cu")
		(net "M_B_CPU0_SB_DQS_DP<9>")
	)
	(segment
		(start 302.313086 -235.406184)
		(end 302.113442 -235.20654)
		(width 0.16002)
		(layer "In2.Cu")
		(net "M_B_CPU0_SB_DQS_DP<9>")
	)
	(segment
		(start 297.05427 -236.132624)
		(end 297.026076 -236.160818)
		(width 0.16002)
		(layer "In2.Cu")
		(net "M_B_CPU0_SB_DQS_DP<9>")
	)
	(segment
		(start 315.009784 -236.676438)
		(end 314.561982 -236.51845)
		(width 0.18288)
		(layer "In2.Cu")
		(net "M_B_CPU0_SB_DQS_DP<9>")
	)
	(segment
		(start 320.83756 -239.884204)
		(end 320.449448 -239.496092)
		(width 0.18288)
		(layer "In2.Cu")
		(net "M_B_CPU0_SB_DQS_DP<9>")
	)
	(segment
		(start 322.353432 -241.400076)
		(end 322.353432 -241.224054)
		(width 0.18288)
		(layer "In2.Cu")
		(net "M_B_CPU0_SB_DQS_DP<9>")
	)
	(segment
		(start 295.688766 -237.808516)
		(end 295.107868 -237.808516)
		(width 0.18288)
		(layer "In2.Cu")
		(net "M_B_CPU0_SB_DQS_DP<9>")
	)
	(segment
		(start 302.097186 -235.20654)
		(end 302.068992 -235.178346)
		(width 0.16002)
		(layer "In2.Cu")
		(net "M_B_CPU0_SB_DQS_DP<9>")
	)
	(segment
		(start 297.298364 -235.88853)
		(end 297.27017 -235.916724)
		(width 0.16002)
		(layer "In2.Cu")
		(net "M_B_CPU0_SB_DQS_DP<9>")
	)
	(segment
		(start 297.468036 -235.718858)
		(end 297.298364 -235.88853)
		(width 0.18288)
		(layer "In2.Cu")
		(net "M_B_CPU0_SB_DQS_DP<9>")
	)
	(segment
		(start 332.32598 -241.920014)
		(end 332.092554 -241.920014)
		(width 0.088646)
		(layer "In2.Cu")
		(net "M_B_CPU0_SB_DQS_DP<9>")
	)
	(segment
		(start 297.026076 -236.160818)
		(end 296.84726 -236.339634)
		(width 0.18288)
		(layer "In2.Cu")
		(net "M_B_CPU0_SB_DQS_DP<9>")
	)
	(segment
		(start 300.69155 -235.104432)
		(end 300.617636 -235.178346)
		(width 0.18288)
		(layer "In2.Cu")
		(net "M_B_CPU0_SB_DQS_DP<9>")
	)
	(segment
		(start 304.762154 -235.944664)
		(end 304.56251 -236.144308)
		(width 0.16002)
		(layer "In2.Cu")
		(net "M_B_CPU0_SB_DQS_DP<9>")
	)
	(segment
		(start 295.107868 -237.808516)
		(end 294.904414 -238.01197)
		(width 0.18288)
		(layer "In2.Cu")
		(net "M_B_CPU0_SB_DQS_DP<9>")
	)
	(segment
		(start 314.20308 -236.51845)
		(end 313.954668 -236.270038)
		(width 0.18288)
		(layer "In2.Cu")
		(net "M_B_CPU0_SB_DQS_DP<9>")
	)
	(segment
		(start 304.351944 -236.37113)
		(end 303.860708 -236.37113)
		(width 0.18288)
		(layer "In2.Cu")
		(net "M_B_CPU0_SB_DQS_DP<9>")
	)
	(segment
		(start 334.018636 -241.97056)
		(end 334.008222 -241.976656)
		(width 0.088646)
		(layer "In2.Cu")
		(net "M_B_CPU0_SB_DQS_DP<9>")
	)
	(segment
		(start 331.004164 -242.176046)
		(end 323.305424 -242.176046)
		(width 0.18288)
		(layer "In2.Cu")
		(net "M_B_CPU0_SB_DQS_DP<9>")
	)
	(segment
		(start 300.373542 -235.42244)
		(end 300.345348 -235.450634)
		(width 0.16002)
		(layer "In2.Cu")
		(net "M_B_CPU0_SB_DQS_DP<9>")
	)
	(segment
		(start 301.995078 -235.104432)
		(end 300.69155 -235.104432)
		(width 0.18288)
		(layer "In2.Cu")
		(net "M_B_CPU0_SB_DQS_DP<9>")
	)
	(segment
		(start 318.035686 -237.930944)
		(end 317.873126 -237.998254)
		(width 0.18288)
		(layer "In2.Cu")
		(net "M_B_CPU0_SB_DQS_DP<9>")
	)
	(segment
		(start 319.786 -238.656622)
		(end 319.27927 -238.446564)
		(width 0.18288)
		(layer "In2.Cu")
		(net "M_B_CPU0_SB_DQS_DP<9>")
	)
	(segment
		(start 321.40144 -240.448084)
		(end 321.40144 -240.272062)
		(width 0.18288)
		(layer "In2.Cu")
		(net "M_B_CPU0_SB_DQS_DP<9>")
	)
	(segment
		(start 298.80433 -235.991654)
		(end 298.531534 -235.718858)
		(width 0.18288)
		(layer "In2.Cu")
		(net "M_B_CPU0_SB_DQS_DP<9>")
	)
	(segment
		(start 298.531534 -235.718858)
		(end 297.468036 -235.718858)
		(width 0.18288)
		(layer "In2.Cu")
		(net "M_B_CPU0_SB_DQS_DP<9>")
	)
	(segment
		(start 321.965574 -240.836196)
		(end 321.789552 -240.836196)
		(width 0.18288)
		(layer "In2.Cu")
		(net "M_B_CPU0_SB_DQS_DP<9>")
	)
	(segment
		(start 300.070266 -235.725716)
		(end 299.458888 -235.725716)
		(width 0.18288)
		(layer "In2.Cu")
		(net "M_B_CPU0_SB_DQS_DP<9>")
	)
	(segment
		(start 316.792102 -237.415324)
		(end 316.629542 -237.482634)
		(width 0.18288)
		(layer "In2.Cu")
		(net "M_B_CPU0_SB_DQS_DP<9>")
	)
	(segment
		(start 310.695848 -236.542834)
		(end 310.391556 -236.847126)
		(width 0.18288)
		(layer "In2.Cu")
		(net "M_B_CPU0_SB_DQS_DP<9>")
	)
	(segment
		(start 335.362804 -241.988086)
		(end 335.332578 -241.97056)
		(width 0.088646)
		(layer "In2.Cu")
		(net "M_B_CPU0_SB_DQS_DP<9>")
	)
	(arc
		(start 334.393032 -241.97056)
		(mid 334.205834 -241.920417)
		(end 334.018636 -241.97056)
		(width 0.088646)
		(layer "In2.Cu")
		(net "M_B_CPU0_SB_DQS_DP<9>")
	)
	(arc
		(start 332.512924 -241.97056)
		(mid 332.422775 -241.932994)
		(end 332.32598 -241.920014)
		(width 0.088646)
		(layer "In2.Cu")
		(net "M_B_CPU0_SB_DQS_DP<9>")
	)
	(arc
		(start 334.947768 -241.976656)
		(mid 334.66959 -242.046379)
		(end 334.393032 -241.97056)
		(width 0.088646)
		(layer "In2.Cu")
		(net "M_B_CPU0_SB_DQS_DP<9>")
	)
	(arc
		(start 335.621884 -242.090702)
		(mid 335.495493 -242.068664)
		(end 335.383886 -242.005358)
		(width 0.088646)
		(layer "In2.Cu")
		(net "M_B_CPU0_SB_DQS_DP<9>")
	)
	(arc
		(start 335.332578 -241.97056)
		(mid 335.14538 -241.920417)
		(end 334.958182 -241.97056)
		(width 0.088646)
		(layer "In2.Cu")
		(net "M_B_CPU0_SB_DQS_DP<9>")
	)
	(arc
		(start 333.452978 -241.97056)
		(mid 333.26578 -241.920417)
		(end 333.078582 -241.97056)
		(width 0.088646)
		(layer "In2.Cu")
		(net "M_B_CPU0_SB_DQS_DP<9>")
	)
	(arc
		(start 333.068168 -241.976656)
		(mid 332.789736 -242.046502)
		(end 332.512924 -241.97056)
		(width 0.088646)
		(layer "In2.Cu")
		(net "M_B_CPU0_SB_DQS_DP<9>")
	)
	(arc
		(start 334.008222 -241.976656)
		(mid 333.72979 -242.046502)
		(end 333.452978 -241.97056)
		(width 0.088646)
		(layer "In2.Cu")
		(net "M_B_CPU0_SB_DQS_DP<9>")
	)
	(segment
		(start 299.004482 -199.01662)
		(end 297.899582 -199.01662)
		(width 0.20066)
		(layer "F.Cu")
		(net "M_B_CPU0_SB_DQS_DP<8>")
	)
	(segment
		(start 295.403016 -198.853044)
		(end 295.141904 -198.591932)
		(width 0.20066)
		(layer "F.Cu")
		(net "M_B_CPU0_SB_DQS_DP<8>")
	)
	(segment
		(start 291.09162 -199.277986)
		(end 290.830254 -199.01662)
		(width 0.20066)
		(layer "F.Cu")
		(net "M_B_CPU0_SB_DQS_DP<8>")
	)
	(segment
		(start 297.148504 -199.277986)
		(end 296.543984 -199.277986)
		(width 0.20066)
		(layer "F.Cu")
		(net "M_B_CPU0_SB_DQS_DP<8>")
	)
	(segment
		(start 292.922198 -198.591678)
		(end 292.680898 -198.591678)
		(width 0.101854)
		(layer "F.Cu")
		(net "M_B_CPU0_SB_DQS_DP<8>")
	)
	(segment
		(start 291.848286 -198.855584)
		(end 291.425884 -199.277986)
		(width 0.20066)
		(layer "F.Cu")
		(net "M_B_CPU0_SB_DQS_DP<8>")
	)
	(segment
		(start 296.543984 -199.277986)
		(end 295.907968 -198.853044)
		(width 0.20066)
		(layer "F.Cu")
		(net "M_B_CPU0_SB_DQS_DP<8>")
	)
	(segment
		(start 291.425884 -199.277986)
		(end 291.09162 -199.277986)
		(width 0.20066)
		(layer "F.Cu")
		(net "M_B_CPU0_SB_DQS_DP<8>")
	)
	(segment
		(start 290.830254 -199.01662)
		(end 290.355782 -199.01662)
		(width 0.20066)
		(layer "F.Cu")
		(net "M_B_CPU0_SB_DQS_DP<8>")
	)
	(segment
		(start 295.907968 -198.853044)
		(end 295.403016 -198.853044)
		(width 0.20066)
		(layer "F.Cu")
		(net "M_B_CPU0_SB_DQS_DP<8>")
	)
	(segment
		(start 335.615534 -225.739198)
		(end 335.615534 -225.203258)
		(width 0.20066)
		(layer "F.Cu")
		(net "M_B_CPU0_SB_DQS_DP<8>")
	)
	(segment
		(start 295.000172 -198.591678)
		(end 292.922198 -198.591678)
		(width 0.1016)
		(layer "F.Cu")
		(net "M_B_CPU0_SB_DQS_DP<8>")
	)
	(segment
		(start 292.67531 -198.58609)
		(end 292.477952 -198.58609)
		(width 0.20066)
		(layer "F.Cu")
		(net "M_B_CPU0_SB_DQS_DP<8>")
	)
	(segment
		(start 292.208458 -198.855584)
		(end 291.848286 -198.855584)
		(width 0.20066)
		(layer "F.Cu")
		(net "M_B_CPU0_SB_DQS_DP<8>")
	)
	(segment
		(start 295.000426 -198.591932)
		(end 295.000172 -198.591678)
		(width 0.1016)
		(layer "F.Cu")
		(net "M_B_CPU0_SB_DQS_DP<8>")
	)
	(segment
		(start 292.477952 -198.58609)
		(end 292.208458 -198.855584)
		(width 0.20066)
		(layer "F.Cu")
		(net "M_B_CPU0_SB_DQS_DP<8>")
	)
	(segment
		(start 295.141904 -198.591932)
		(end 295.000426 -198.591932)
		(width 0.20066)
		(layer "F.Cu")
		(net "M_B_CPU0_SB_DQS_DP<8>")
	)
	(segment
		(start 292.680898 -198.591678)
		(end 292.67531 -198.58609)
		(width 0.101854)
		(layer "F.Cu")
		(net "M_B_CPU0_SB_DQS_DP<8>")
	)
	(segment
		(start 297.899582 -199.01662)
		(end 297.40987 -199.01662)
		(width 0.20066)
		(layer "F.Cu")
		(net "M_B_CPU0_SB_DQS_DP<8>")
	)
	(segment
		(start 297.40987 -199.01662)
		(end 297.148504 -199.277986)
		(width 0.20066)
		(layer "F.Cu")
		(net "M_B_CPU0_SB_DQS_DP<8>")
	)
	(segment
		(start 299.271944 -199.284082)
		(end 299.004482 -199.01662)
		(width 0.18288)
		(layer "In4.Cu")
		(net "M_B_CPU0_SB_DQS_DP<8>")
	)
	(segment
		(start 310.717184 -198.281544)
		(end 307.247036 -198.281544)
		(width 0.18288)
		(layer "In4.Cu")
		(net "M_B_CPU0_SB_DQS_DP<8>")
	)
	(segment
		(start 313.162696 -198.69023)
		(end 311.12587 -198.69023)
		(width 0.18288)
		(layer "In4.Cu")
		(net "M_B_CPU0_SB_DQS_DP<8>")
	)
	(segment
		(start 332.530958 -223.840802)
		(end 331.928978 -223.238822)
		(width 0.088646)
		(layer "In4.Cu")
		(net "M_B_CPU0_SB_DQS_DP<8>")
	)
	(segment
		(start 319.431416 -204.958696)
		(end 313.162696 -198.69023)
		(width 0.18288)
		(layer "In4.Cu")
		(net "M_B_CPU0_SB_DQS_DP<8>")
	)
	(segment
		(start 330.731622 -222.323914)
		(end 330.671932 -222.264224)
		(width 0.088646)
		(layer "In4.Cu")
		(net "M_B_CPU0_SB_DQS_DP<8>")
	)
	(segment
		(start 331.928978 -223.118172)
		(end 331.13472 -222.323914)
		(width 0.088646)
		(layer "In4.Cu")
		(net "M_B_CPU0_SB_DQS_DP<8>")
	)
	(segment
		(start 331.928978 -223.238822)
		(end 331.928978 -223.118172)
		(width 0.088646)
		(layer "In4.Cu")
		(net "M_B_CPU0_SB_DQS_DP<8>")
	)
	(segment
		(start 332.89113 -224.389442)
		(end 332.89113 -224.373948)
		(width 0.088646)
		(layer "In4.Cu")
		(net "M_B_CPU0_SB_DQS_DP<8>")
	)
	(segment
		(start 306.89804 -198.63054)
		(end 303.797716 -198.63054)
		(width 0.18288)
		(layer "In4.Cu")
		(net "M_B_CPU0_SB_DQS_DP<8>")
	)
	(segment
		(start 334.018636 -224.7138)
		(end 334.008222 -224.707704)
		(width 0.088646)
		(layer "In4.Cu")
		(net "M_B_CPU0_SB_DQS_DP<8>")
	)
	(segment
		(start 330.648564 -222.264224)
		(end 328.893932 -222.264224)
		(width 0.18288)
		(layer "In4.Cu")
		(net "M_B_CPU0_SB_DQS_DP<8>")
	)
	(segment
		(start 333.452978 -224.7138)
		(end 333.452978 -224.713546)
		(width 0.088646)
		(layer "In4.Cu")
		(net "M_B_CPU0_SB_DQS_DP<8>")
	)
	(segment
		(start 299.938694 -199.495918)
		(end 299.726858 -199.284082)
		(width 0.18288)
		(layer "In4.Cu")
		(net "M_B_CPU0_SB_DQS_DP<8>")
	)
	(segment
		(start 311.12587 -198.69023)
		(end 310.717184 -198.281544)
		(width 0.18288)
		(layer "In4.Cu")
		(net "M_B_CPU0_SB_DQS_DP<8>")
	)
	(segment
		(start 302.932338 -199.495918)
		(end 299.938694 -199.495918)
		(width 0.18288)
		(layer "In4.Cu")
		(net "M_B_CPU0_SB_DQS_DP<8>")
	)
	(segment
		(start 303.797716 -198.63054)
		(end 302.932338 -199.495918)
		(width 0.18288)
		(layer "In4.Cu")
		(net "M_B_CPU0_SB_DQS_DP<8>")
	)
	(segment
		(start 299.726858 -199.284082)
		(end 299.271944 -199.284082)
		(width 0.18288)
		(layer "In4.Cu")
		(net "M_B_CPU0_SB_DQS_DP<8>")
	)
	(segment
		(start 307.247036 -198.281544)
		(end 306.89804 -198.63054)
		(width 0.18288)
		(layer "In4.Cu")
		(net "M_B_CPU0_SB_DQS_DP<8>")
	)
	(segment
		(start 330.671932 -222.264224)
		(end 330.648564 -222.264224)
		(width 0.088646)
		(layer "In4.Cu")
		(net "M_B_CPU0_SB_DQS_DP<8>")
	)
	(segment
		(start 335.615534 -225.203258)
		(end 335.346802 -225.203258)
		(width 0.088646)
		(layer "In4.Cu")
		(net "M_B_CPU0_SB_DQS_DP<8>")
	)
	(segment
		(start 333.078582 -224.7138)
		(end 333.077058 -224.713038)
		(width 0.088646)
		(layer "In4.Cu")
		(net "M_B_CPU0_SB_DQS_DP<8>")
	)
	(segment
		(start 324.93204 -218.302078)
		(end 319.431416 -204.958696)
		(width 0.18288)
		(layer "In4.Cu")
		(net "M_B_CPU0_SB_DQS_DP<8>")
	)
	(segment
		(start 333.077058 -224.713038)
		(end 333.069692 -224.70872)
		(width 0.088646)
		(layer "In4.Cu")
		(net "M_B_CPU0_SB_DQS_DP<8>")
	)
	(segment
		(start 328.893932 -222.264224)
		(end 324.93204 -218.302078)
		(width 0.18288)
		(layer "In4.Cu")
		(net "M_B_CPU0_SB_DQS_DP<8>")
	)
	(segment
		(start 331.13472 -222.323914)
		(end 330.731622 -222.323914)
		(width 0.088646)
		(layer "In4.Cu")
		(net "M_B_CPU0_SB_DQS_DP<8>")
	)
	(arc
		(start 334.961738 -224.715578)
		(mid 334.958427 -224.713689)
		(end 334.955134 -224.711768)
		(width 0.088646)
		(layer "In4.Cu")
		(net "M_B_CPU0_SB_DQS_DP<8>")
	)
	(arc
		(start 332.545436 -223.854264)
		(mid 332.538108 -223.847629)
		(end 332.530958 -223.840802)
		(width 0.088646)
		(layer "In4.Cu")
		(net "M_B_CPU0_SB_DQS_DP<8>")
	)
	(arc
		(start 335.267808 -225.162364)
		(mid 335.241787 -225.116879)
		(end 335.224628 -225.067368)
		(width 0.088646)
		(layer "In4.Cu")
		(net "M_B_CPU0_SB_DQS_DP<8>")
	)
	(arc
		(start 333.452978 -224.713546)
		(mid 333.265809 -224.76385)
		(end 333.078582 -224.7138)
		(width 0.088646)
		(layer "In4.Cu")
		(net "M_B_CPU0_SB_DQS_DP<8>")
	)
	(arc
		(start 332.608936 -223.899984)
		(mid 332.575982 -223.878795)
		(end 332.545436 -223.854264)
		(width 0.088646)
		(layer "In4.Cu")
		(net "M_B_CPU0_SB_DQS_DP<8>")
	)
	(arc
		(start 333.069692 -224.70872)
		(mid 332.938778 -224.57236)
		(end 332.89113 -224.389442)
		(width 0.088646)
		(layer "In4.Cu")
		(net "M_B_CPU0_SB_DQS_DP<8>")
	)
	(arc
		(start 335.224628 -225.067368)
		(mid 335.128742 -224.864901)
		(end 334.961738 -224.715578)
		(width 0.088646)
		(layer "In4.Cu")
		(net "M_B_CPU0_SB_DQS_DP<8>")
	)
	(arc
		(start 332.89113 -224.373948)
		(mid 332.81176 -224.100214)
		(end 332.608936 -223.899984)
		(width 0.088646)
		(layer "In4.Cu")
		(net "M_B_CPU0_SB_DQS_DP<8>")
	)
	(arc
		(start 334.008222 -224.707704)
		(mid 333.72979 -224.637858)
		(end 333.452978 -224.7138)
		(width 0.088646)
		(layer "In4.Cu")
		(net "M_B_CPU0_SB_DQS_DP<8>")
	)
	(arc
		(start 334.393032 -224.7138)
		(mid 334.205834 -224.763943)
		(end 334.018636 -224.7138)
		(width 0.088646)
		(layer "In4.Cu")
		(net "M_B_CPU0_SB_DQS_DP<8>")
	)
	(arc
		(start 334.955134 -224.711768)
		(mid 334.673796 -224.637906)
		(end 334.393032 -224.7138)
		(width 0.088646)
		(layer "In4.Cu")
		(net "M_B_CPU0_SB_DQS_DP<8>")
	)
	(arc
		(start 335.346802 -225.203258)
		(mid 335.302272 -225.192504)
		(end 335.267808 -225.162364)
		(width 0.088646)
		(layer "In4.Cu")
		(net "M_B_CPU0_SB_DQS_DP<8>")
	)
	(segment
		(start 295.000172 -207.941672)
		(end 292.922198 -207.941672)
		(width 0.1016)
		(layer "F.Cu")
		(net "M_B_CPU0_SB_DQS_DP<7>")
	)
	(segment
		(start 338.90458 -227.645214)
		(end 338.904834 -227.64496)
		(width 0.20066)
		(layer "F.Cu")
		(net "M_B_CPU0_SB_DQS_DP<7>")
	)
	(segment
		(start 338.90458 -228.1809)
		(end 338.90458 -227.645214)
		(width 0.20066)
		(layer "F.Cu")
		(net "M_B_CPU0_SB_DQS_DP<7>")
	)
	(segment
		(start 296.543984 -208.62798)
		(end 295.907968 -208.203038)
		(width 0.20066)
		(layer "F.Cu")
		(net "M_B_CPU0_SB_DQS_DP<7>")
	)
	(segment
		(start 295.141904 -207.941926)
		(end 295.000426 -207.941926)
		(width 0.20066)
		(layer "F.Cu")
		(net "M_B_CPU0_SB_DQS_DP<7>")
	)
	(segment
		(start 292.208458 -208.205578)
		(end 291.848286 -208.205578)
		(width 0.20066)
		(layer "F.Cu")
		(net "M_B_CPU0_SB_DQS_DP<7>")
	)
	(segment
		(start 292.922198 -207.941672)
		(end 292.680898 -207.941672)
		(width 0.101854)
		(layer "F.Cu")
		(net "M_B_CPU0_SB_DQS_DP<7>")
	)
	(segment
		(start 292.67531 -207.936084)
		(end 292.477952 -207.936084)
		(width 0.20066)
		(layer "F.Cu")
		(net "M_B_CPU0_SB_DQS_DP<7>")
	)
	(segment
		(start 297.899582 -208.366614)
		(end 297.40987 -208.366614)
		(width 0.20066)
		(layer "F.Cu")
		(net "M_B_CPU0_SB_DQS_DP<7>")
	)
	(segment
		(start 292.680898 -207.941672)
		(end 292.67531 -207.936084)
		(width 0.101854)
		(layer "F.Cu")
		(net "M_B_CPU0_SB_DQS_DP<7>")
	)
	(segment
		(start 295.403016 -208.203038)
		(end 295.141904 -207.941926)
		(width 0.20066)
		(layer "F.Cu")
		(net "M_B_CPU0_SB_DQS_DP<7>")
	)
	(segment
		(start 292.477952 -207.936084)
		(end 292.208458 -208.205578)
		(width 0.20066)
		(layer "F.Cu")
		(net "M_B_CPU0_SB_DQS_DP<7>")
	)
	(segment
		(start 295.907968 -208.203038)
		(end 295.403016 -208.203038)
		(width 0.20066)
		(layer "F.Cu")
		(net "M_B_CPU0_SB_DQS_DP<7>")
	)
	(segment
		(start 291.09162 -208.62798)
		(end 290.830254 -208.366614)
		(width 0.20066)
		(layer "F.Cu")
		(net "M_B_CPU0_SB_DQS_DP<7>")
	)
	(segment
		(start 295.000426 -207.941926)
		(end 295.000172 -207.941672)
		(width 0.1016)
		(layer "F.Cu")
		(net "M_B_CPU0_SB_DQS_DP<7>")
	)
	(segment
		(start 291.848286 -208.205578)
		(end 291.425884 -208.62798)
		(width 0.20066)
		(layer "F.Cu")
		(net "M_B_CPU0_SB_DQS_DP<7>")
	)
	(segment
		(start 299.004482 -208.366614)
		(end 297.899582 -208.366614)
		(width 0.20066)
		(layer "F.Cu")
		(net "M_B_CPU0_SB_DQS_DP<7>")
	)
	(segment
		(start 290.830254 -208.366614)
		(end 290.355782 -208.366614)
		(width 0.20066)
		(layer "F.Cu")
		(net "M_B_CPU0_SB_DQS_DP<7>")
	)
	(segment
		(start 297.40987 -208.366614)
		(end 297.148504 -208.62798)
		(width 0.20066)
		(layer "F.Cu")
		(net "M_B_CPU0_SB_DQS_DP<7>")
	)
	(segment
		(start 297.148504 -208.62798)
		(end 296.543984 -208.62798)
		(width 0.20066)
		(layer "F.Cu")
		(net "M_B_CPU0_SB_DQS_DP<7>")
	)
	(segment
		(start 291.425884 -208.62798)
		(end 291.09162 -208.62798)
		(width 0.20066)
		(layer "F.Cu")
		(net "M_B_CPU0_SB_DQS_DP<7>")
	)
	(segment
		(start 314.208668 -208.017872)
		(end 314.08243 -207.891634)
		(width 0.18288)
		(layer "In2.Cu")
		(net "M_B_CPU0_SB_DQS_DP<7>")
	)
	(segment
		(start 302.188626 -207.800702)
		(end 302.188626 -207.816958)
		(width 0.16002)
		(layer "In2.Cu")
		(net "M_B_CPU0_SB_DQS_DP<7>")
	)
	(segment
		(start 312.159142 -207.629506)
		(end 312.130948 -207.6577)
		(width 0.16002)
		(layer "In2.Cu")
		(net "M_B_CPU0_SB_DQS_DP<7>")
	)
	(segment
		(start 307.942234 -206.909162)
		(end 307.91404 -206.937356)
		(width 0.16002)
		(layer "In2.Cu")
		(net "M_B_CPU0_SB_DQS_DP<7>")
	)
	(segment
		(start 302.365918 -207.62341)
		(end 302.21682 -207.772508)
		(width 0.18288)
		(layer "In2.Cu")
		(net "M_B_CPU0_SB_DQS_DP<7>")
	)
	(segment
		(start 311.761378 -208.02727)
		(end 310.950102 -208.02727)
		(width 0.18288)
		(layer "In2.Cu")
		(net "M_B_CPU0_SB_DQS_DP<7>")
	)
	(segment
		(start 304.817018 -207.43291)
		(end 304.501042 -207.748886)
		(width 0.18288)
		(layer "In2.Cu")
		(net "M_B_CPU0_SB_DQS_DP<7>")
	)
	(segment
		(start 303.545494 -208.08061)
		(end 303.088294 -207.62341)
		(width 0.18288)
		(layer "In2.Cu")
		(net "M_B_CPU0_SB_DQS_DP<7>")
	)
	(segment
		(start 313.534806 -207.34401)
		(end 312.444638 -207.34401)
		(width 0.18288)
		(layer "In2.Cu")
		(net "M_B_CPU0_SB_DQS_DP<7>")
	)
	(segment
		(start 334.301084 -223.575626)
		(end 334.301084 -223.557084)
		(width 0.088646)
		(layer "In2.Cu")
		(net "M_B_CPU0_SB_DQS_DP<7>")
	)
	(segment
		(start 303.088294 -207.62341)
		(end 302.365918 -207.62341)
		(width 0.18288)
		(layer "In2.Cu")
		(net "M_B_CPU0_SB_DQS_DP<7>")
	)
	(segment
		(start 306.84724 -207.229964)
		(end 306.383436 -207.229964)
		(width 0.18288)
		(layer "In2.Cu")
		(net "M_B_CPU0_SB_DQS_DP<7>")
	)
	(segment
		(start 300.294548 -208.713578)
		(end 300.2788 -208.713578)
		(width 0.16002)
		(layer "In2.Cu")
		(net "M_B_CPU0_SB_DQS_DP<7>")
	)
	(segment
		(start 301.944532 -208.044796)
		(end 301.761398 -208.22793)
		(width 0.18288)
		(layer "In2.Cu")
		(net "M_B_CPU0_SB_DQS_DP<7>")
	)
	(segment
		(start 312.130948 -207.673448)
		(end 311.930796 -207.8736)
		(width 0.16002)
		(layer "In2.Cu")
		(net "M_B_CPU0_SB_DQS_DP<7>")
	)
	(segment
		(start 301.761398 -208.22793)
		(end 300.764448 -208.22793)
		(width 0.18288)
		(layer "In2.Cu")
		(net "M_B_CPU0_SB_DQS_DP<7>")
	)
	(segment
		(start 311.886854 -207.901794)
		(end 311.761378 -208.02727)
		(width 0.18288)
		(layer "In2.Cu")
		(net "M_B_CPU0_SB_DQS_DP<7>")
	)
	(segment
		(start 301.972726 -208.016602)
		(end 301.944532 -208.044796)
		(width 0.16002)
		(layer "In2.Cu")
		(net "M_B_CPU0_SB_DQS_DP<7>")
	)
	(segment
		(start 336.180684 -226.83978)
		(end 336.180684 -226.821238)
		(width 0.088646)
		(layer "In2.Cu")
		(net "M_B_CPU0_SB_DQS_DP<7>")
	)
	(segment
		(start 338.904834 -227.64496)
		(end 338.591906 -227.64496)
		(width 0.088646)
		(layer "In2.Cu")
		(net "M_B_CPU0_SB_DQS_DP<7>")
	)
	(segment
		(start 304.169318 -208.08061)
		(end 303.545494 -208.08061)
		(width 0.18288)
		(layer "In2.Cu")
		(net "M_B_CPU0_SB_DQS_DP<7>")
	)
	(segment
		(start 308.125368 -206.726028)
		(end 307.942234 -206.909162)
		(width 0.18288)
		(layer "In2.Cu")
		(net "M_B_CPU0_SB_DQS_DP<7>")
	)
	(segment
		(start 310.950102 -208.02727)
		(end 310.104282 -207.18145)
		(width 0.18288)
		(layer "In2.Cu")
		(net "M_B_CPU0_SB_DQS_DP<7>")
	)
	(segment
		(start 332.079854 -222.019876)
		(end 318.07785 -208.017872)
		(width 0.18288)
		(layer "In2.Cu")
		(net "M_B_CPU0_SB_DQS_DP<7>")
	)
	(segment
		(start 304.256948 -207.99298)
		(end 304.228754 -208.021174)
		(width 0.16002)
		(layer "In2.Cu")
		(net "M_B_CPU0_SB_DQS_DP<7>")
	)
	(segment
		(start 304.472848 -207.792828)
		(end 304.272696 -207.99298)
		(width 0.16002)
		(layer "In2.Cu")
		(net "M_B_CPU0_SB_DQS_DP<7>")
	)
	(segment
		(start 314.038488 -207.86344)
		(end 313.838336 -207.663288)
		(width 0.16002)
		(layer "In2.Cu")
		(net "M_B_CPU0_SB_DQS_DP<7>")
	)
	(segment
		(start 338.591906 -227.64496)
		(end 338.526374 -227.579428)
		(width 0.088646)
		(layer "In2.Cu")
		(net "M_B_CPU0_SB_DQS_DP<7>")
	)
	(segment
		(start 307.346096 -207.5053)
		(end 307.122576 -207.5053)
		(width 0.18288)
		(layer "In2.Cu")
		(net "M_B_CPU0_SB_DQS_DP<7>")
	)
	(segment
		(start 307.69814 -207.153256)
		(end 307.669946 -207.18145)
		(width 0.16002)
		(layer "In2.Cu")
		(net "M_B_CPU0_SB_DQS_DP<7>")
	)
	(segment
		(start 333.372968 -222.079566)
		(end 332.62697 -222.079566)
		(width 0.088646)
		(layer "In2.Cu")
		(net "M_B_CPU0_SB_DQS_DP<7>")
	)
	(segment
		(start 333.596488 -222.302832)
		(end 333.372968 -222.079566)
		(width 0.088646)
		(layer "In2.Cu")
		(net "M_B_CPU0_SB_DQS_DP<7>")
	)
	(segment
		(start 307.91404 -206.953104)
		(end 307.713888 -207.153256)
		(width 0.16002)
		(layer "In2.Cu")
		(net "M_B_CPU0_SB_DQS_DP<7>")
	)
	(segment
		(start 300.129448 -208.86293)
		(end 299.839888 -208.86293)
		(width 0.18288)
		(layer "In2.Cu")
		(net "M_B_CPU0_SB_DQS_DP<7>")
	)
	(segment
		(start 300.522894 -208.469484)
		(end 300.4947 -208.497678)
		(width 0.16002)
		(layer "In2.Cu")
		(net "M_B_CPU0_SB_DQS_DP<7>")
	)
	(segment
		(start 309.64886 -206.726028)
		(end 308.125368 -206.726028)
		(width 0.18288)
		(layer "In2.Cu")
		(net "M_B_CPU0_SB_DQS_DP<7>")
	)
	(segment
		(start 305.735482 -207.509618)
		(end 305.658774 -207.43291)
		(width 0.18288)
		(layer "In2.Cu")
		(net "M_B_CPU0_SB_DQS_DP<7>")
	)
	(segment
		(start 307.91404 -206.937356)
		(end 307.91404 -206.953104)
		(width 0.16002)
		(layer "In2.Cu")
		(net "M_B_CPU0_SB_DQS_DP<7>")
	)
	(segment
		(start 299.839888 -208.86293)
		(end 299.61459 -208.637632)
		(width 0.18288)
		(layer "In2.Cu")
		(net "M_B_CPU0_SB_DQS_DP<7>")
	)
	(segment
		(start 304.228754 -208.021174)
		(end 304.169318 -208.08061)
		(width 0.18288)
		(layer "In2.Cu")
		(net "M_B_CPU0_SB_DQS_DP<7>")
	)
	(segment
		(start 304.272696 -207.99298)
		(end 304.256948 -207.99298)
		(width 0.16002)
		(layer "In2.Cu")
		(net "M_B_CPU0_SB_DQS_DP<7>")
	)
	(segment
		(start 300.250606 -208.741772)
		(end 300.129448 -208.86293)
		(width 0.18288)
		(layer "In2.Cu")
		(net "M_B_CPU0_SB_DQS_DP<7>")
	)
	(segment
		(start 300.4947 -208.513426)
		(end 300.294548 -208.713578)
		(width 0.16002)
		(layer "In2.Cu")
		(net "M_B_CPU0_SB_DQS_DP<7>")
	)
	(segment
		(start 332.56728 -222.019876)
		(end 332.079854 -222.019876)
		(width 0.18288)
		(layer "In2.Cu")
		(net "M_B_CPU0_SB_DQS_DP<7>")
	)
	(segment
		(start 312.130948 -207.6577)
		(end 312.130948 -207.673448)
		(width 0.16002)
		(layer "In2.Cu")
		(net "M_B_CPU0_SB_DQS_DP<7>")
	)
	(segment
		(start 306.103782 -207.509618)
		(end 305.735482 -207.509618)
		(width 0.18288)
		(layer "In2.Cu")
		(net "M_B_CPU0_SB_DQS_DP<7>")
	)
	(segment
		(start 310.076088 -207.153256)
		(end 310.06034 -207.153256)
		(width 0.16002)
		(layer "In2.Cu")
		(net "M_B_CPU0_SB_DQS_DP<7>")
	)
	(segment
		(start 300.2788 -208.713578)
		(end 300.250606 -208.741772)
		(width 0.16002)
		(layer "In2.Cu")
		(net "M_B_CPU0_SB_DQS_DP<7>")
	)
	(segment
		(start 332.62697 -222.079566)
		(end 332.56728 -222.019876)
		(width 0.088646)
		(layer "In2.Cu")
		(net "M_B_CPU0_SB_DQS_DP<7>")
	)
	(segment
		(start 300.4947 -208.497678)
		(end 300.4947 -208.513426)
		(width 0.16002)
		(layer "In2.Cu")
		(net "M_B_CPU0_SB_DQS_DP<7>")
	)
	(segment
		(start 302.21682 -207.772508)
		(end 302.188626 -207.800702)
		(width 0.16002)
		(layer "In2.Cu")
		(net "M_B_CPU0_SB_DQS_DP<7>")
	)
	(segment
		(start 335.889346 -225.69805)
		(end 335.898236 -225.69297)
		(width 0.088646)
		(layer "In2.Cu")
		(net "M_B_CPU0_SB_DQS_DP<7>")
	)
	(segment
		(start 334.488536 -223.899984)
		(end 334.479646 -223.894904)
		(width 0.088646)
		(layer "In2.Cu")
		(net "M_B_CPU0_SB_DQS_DP<7>")
	)
	(segment
		(start 312.444638 -207.34401)
		(end 312.159142 -207.629506)
		(width 0.18288)
		(layer "In2.Cu")
		(net "M_B_CPU0_SB_DQS_DP<7>")
	)
	(segment
		(start 311.930796 -207.8736)
		(end 311.915048 -207.8736)
		(width 0.16002)
		(layer "In2.Cu")
		(net "M_B_CPU0_SB_DQS_DP<7>")
	)
	(segment
		(start 306.383436 -207.229964)
		(end 306.103782 -207.509618)
		(width 0.18288)
		(layer "In2.Cu")
		(net "M_B_CPU0_SB_DQS_DP<7>")
	)
	(segment
		(start 337.307682 -227.155502)
		(end 337.29295 -227.146866)
		(width 0.088646)
		(layer "In2.Cu")
		(net "M_B_CPU0_SB_DQS_DP<7>")
	)
	(segment
		(start 309.831994 -206.909162)
		(end 309.64886 -206.726028)
		(width 0.18288)
		(layer "In2.Cu")
		(net "M_B_CPU0_SB_DQS_DP<7>")
	)
	(segment
		(start 310.06034 -207.153256)
		(end 309.860188 -206.953104)
		(width 0.16002)
		(layer "In2.Cu")
		(net "M_B_CPU0_SB_DQS_DP<7>")
	)
	(segment
		(start 313.810142 -207.619346)
		(end 313.534806 -207.34401)
		(width 0.18288)
		(layer "In2.Cu")
		(net "M_B_CPU0_SB_DQS_DP<7>")
	)
	(segment
		(start 307.669946 -207.18145)
		(end 307.346096 -207.5053)
		(width 0.18288)
		(layer "In2.Cu")
		(net "M_B_CPU0_SB_DQS_DP<7>")
	)
	(segment
		(start 338.253578 -227.159058)
		(end 338.23275 -227.146866)
		(width 0.088646)
		(layer "In2.Cu")
		(net "M_B_CPU0_SB_DQS_DP<7>")
	)
	(segment
		(start 335.898236 -226.341686)
		(end 335.890362 -226.337114)
		(width 0.088646)
		(layer "In2.Cu")
		(net "M_B_CPU0_SB_DQS_DP<7>")
	)
	(segment
		(start 301.988982 -208.016602)
		(end 301.972726 -208.016602)
		(width 0.16002)
		(layer "In2.Cu")
		(net "M_B_CPU0_SB_DQS_DP<7>")
	)
	(segment
		(start 311.915048 -207.8736)
		(end 311.886854 -207.901794)
		(width 0.16002)
		(layer "In2.Cu")
		(net "M_B_CPU0_SB_DQS_DP<7>")
	)
	(segment
		(start 307.713888 -207.153256)
		(end 307.69814 -207.153256)
		(width 0.16002)
		(layer "In2.Cu")
		(net "M_B_CPU0_SB_DQS_DP<7>")
	)
	(segment
		(start 309.860188 -206.937356)
		(end 309.831994 -206.909162)
		(width 0.16002)
		(layer "In2.Cu")
		(net "M_B_CPU0_SB_DQS_DP<7>")
	)
	(segment
		(start 304.472848 -207.77708)
		(end 304.472848 -207.792828)
		(width 0.16002)
		(layer "In2.Cu")
		(net "M_B_CPU0_SB_DQS_DP<7>")
	)
	(segment
		(start 300.764448 -208.22793)
		(end 300.522894 -208.469484)
		(width 0.18288)
		(layer "In2.Cu")
		(net "M_B_CPU0_SB_DQS_DP<7>")
	)
	(segment
		(start 310.104282 -207.18145)
		(end 310.076088 -207.153256)
		(width 0.16002)
		(layer "In2.Cu")
		(net "M_B_CPU0_SB_DQS_DP<7>")
	)
	(segment
		(start 305.658774 -207.43291)
		(end 304.817018 -207.43291)
		(width 0.18288)
		(layer "In2.Cu")
		(net "M_B_CPU0_SB_DQS_DP<7>")
	)
	(segment
		(start 309.860188 -206.953104)
		(end 309.860188 -206.937356)
		(width 0.16002)
		(layer "In2.Cu")
		(net "M_B_CPU0_SB_DQS_DP<7>")
	)
	(segment
		(start 302.188626 -207.816958)
		(end 301.988982 -208.016602)
		(width 0.16002)
		(layer "In2.Cu")
		(net "M_B_CPU0_SB_DQS_DP<7>")
	)
	(segment
		(start 314.054236 -207.86344)
		(end 314.038488 -207.86344)
		(width 0.16002)
		(layer "In2.Cu")
		(net "M_B_CPU0_SB_DQS_DP<7>")
	)
	(segment
		(start 304.501042 -207.748886)
		(end 304.472848 -207.77708)
		(width 0.16002)
		(layer "In2.Cu")
		(net "M_B_CPU0_SB_DQS_DP<7>")
	)
	(segment
		(start 314.08243 -207.891634)
		(end 314.054236 -207.86344)
		(width 0.16002)
		(layer "In2.Cu")
		(net "M_B_CPU0_SB_DQS_DP<7>")
	)
	(segment
		(start 299.61459 -208.637632)
		(end 299.2755 -208.637632)
		(width 0.18288)
		(layer "In2.Cu")
		(net "M_B_CPU0_SB_DQS_DP<7>")
	)
	(segment
		(start 334.770984 -224.389442)
		(end 334.770984 -224.379536)
		(width 0.088646)
		(layer "In2.Cu")
		(net "M_B_CPU0_SB_DQS_DP<7>")
	)
	(segment
		(start 334.018636 -223.085914)
		(end 334.009746 -223.080834)
		(width 0.088646)
		(layer "In2.Cu")
		(net "M_B_CPU0_SB_DQS_DP<7>")
	)
	(segment
		(start 313.838336 -207.663288)
		(end 313.838336 -207.64754)
		(width 0.16002)
		(layer "In2.Cu")
		(net "M_B_CPU0_SB_DQS_DP<7>")
	)
	(segment
		(start 335.890362 -226.337114)
		(end 335.889346 -226.336606)
		(width 0.088646)
		(layer "In2.Cu")
		(net "M_B_CPU0_SB_DQS_DP<7>")
	)
	(segment
		(start 307.122576 -207.5053)
		(end 306.84724 -207.229964)
		(width 0.18288)
		(layer "In2.Cu")
		(net "M_B_CPU0_SB_DQS_DP<7>")
	)
	(segment
		(start 299.2755 -208.637632)
		(end 299.004482 -208.366614)
		(width 0.18288)
		(layer "In2.Cu")
		(net "M_B_CPU0_SB_DQS_DP<7>")
	)
	(segment
		(start 318.07785 -208.017872)
		(end 314.208668 -208.017872)
		(width 0.18288)
		(layer "In2.Cu")
		(net "M_B_CPU0_SB_DQS_DP<7>")
	)
	(segment
		(start 313.838336 -207.64754)
		(end 313.810142 -207.619346)
		(width 0.16002)
		(layer "In2.Cu")
		(net "M_B_CPU0_SB_DQS_DP<7>")
	)
	(arc
		(start 335.898236 -225.69297)
		(mid 336.105214 -224.920501)
		(end 335.332832 -224.7138)
		(width 0.088646)
		(layer "In2.Cu")
		(net "M_B_CPU0_SB_DQS_DP<7>")
	)
	(arc
		(start 336.742278 -227.155502)
		(mid 336.371555 -227.157594)
		(end 336.180684 -226.83978)
		(width 0.088646)
		(layer "In2.Cu")
		(net "M_B_CPU0_SB_DQS_DP<7>")
	)
	(arc
		(start 334.479646 -223.894904)
		(mid 334.348732 -223.758544)
		(end 334.301084 -223.575626)
		(width 0.088646)
		(layer "In2.Cu")
		(net "M_B_CPU0_SB_DQS_DP<7>")
	)
	(arc
		(start 334.009746 -223.080834)
		(mid 333.878832 -222.944474)
		(end 333.831184 -222.761556)
		(width 0.088646)
		(layer "In2.Cu")
		(net "M_B_CPU0_SB_DQS_DP<7>")
	)
	(arc
		(start 337.29295 -227.146866)
		(mid 337.016475 -227.079546)
		(end 336.742278 -227.155502)
		(width 0.088646)
		(layer "In2.Cu")
		(net "M_B_CPU0_SB_DQS_DP<7>")
	)
	(arc
		(start 335.889346 -226.336606)
		(mid 335.710749 -226.017328)
		(end 335.889346 -225.69805)
		(width 0.088646)
		(layer "In2.Cu")
		(net "M_B_CPU0_SB_DQS_DP<7>")
	)
	(arc
		(start 335.332832 -224.7138)
		(mid 334.958357 -224.713754)
		(end 334.770984 -224.389442)
		(width 0.088646)
		(layer "In2.Cu")
		(net "M_B_CPU0_SB_DQS_DP<7>")
	)
	(arc
		(start 336.180684 -226.821238)
		(mid 336.102573 -226.544289)
		(end 335.898236 -226.341686)
		(width 0.088646)
		(layer "In2.Cu")
		(net "M_B_CPU0_SB_DQS_DP<7>")
	)
	(arc
		(start 333.831184 -222.761556)
		(mid 333.769158 -222.50389)
		(end 333.596488 -222.302832)
		(width 0.088646)
		(layer "In2.Cu")
		(net "M_B_CPU0_SB_DQS_DP<7>")
	)
	(arc
		(start 337.682078 -227.155502)
		(mid 337.49488 -227.205645)
		(end 337.307682 -227.155502)
		(width 0.088646)
		(layer "In2.Cu")
		(net "M_B_CPU0_SB_DQS_DP<7>")
	)
	(arc
		(start 334.770984 -224.379536)
		(mid 334.692873 -224.102587)
		(end 334.488536 -223.899984)
		(width 0.088646)
		(layer "In2.Cu")
		(net "M_B_CPU0_SB_DQS_DP<7>")
	)
	(arc
		(start 338.526374 -227.579428)
		(mid 338.43913 -227.33734)
		(end 338.253578 -227.159058)
		(width 0.088646)
		(layer "In2.Cu")
		(net "M_B_CPU0_SB_DQS_DP<7>")
	)
	(arc
		(start 338.23275 -227.146866)
		(mid 337.956275 -227.079546)
		(end 337.682078 -227.155502)
		(width 0.088646)
		(layer "In2.Cu")
		(net "M_B_CPU0_SB_DQS_DP<7>")
	)
	(arc
		(start 334.301084 -223.557084)
		(mid 334.220922 -223.284895)
		(end 334.018636 -223.085914)
		(width 0.088646)
		(layer "In2.Cu")
		(net "M_B_CPU0_SB_DQS_DP<7>")
	)
	(segment
		(start 295.000172 -217.291666)
		(end 292.922198 -217.291666)
		(width 0.1016)
		(layer "F.Cu")
		(net "M_B_CPU0_SB_DQS_DP<6>")
	)
	(segment
		(start 291.09162 -217.977974)
		(end 290.830254 -217.716608)
		(width 0.20066)
		(layer "F.Cu")
		(net "M_B_CPU0_SB_DQS_DP<6>")
	)
	(segment
		(start 295.907968 -217.553032)
		(end 295.403016 -217.553032)
		(width 0.20066)
		(layer "F.Cu")
		(net "M_B_CPU0_SB_DQS_DP<6>")
	)
	(segment
		(start 292.67531 -217.286078)
		(end 292.477952 -217.286078)
		(width 0.20066)
		(layer "F.Cu")
		(net "M_B_CPU0_SB_DQS_DP<6>")
	)
	(segment
		(start 299.004482 -217.716608)
		(end 297.899582 -217.716608)
		(width 0.20066)
		(layer "F.Cu")
		(net "M_B_CPU0_SB_DQS_DP<6>")
	)
	(segment
		(start 295.000426 -217.29192)
		(end 295.000172 -217.291666)
		(width 0.1016)
		(layer "F.Cu")
		(net "M_B_CPU0_SB_DQS_DP<6>")
	)
	(segment
		(start 338.90458 -233.064304)
		(end 338.904834 -233.06405)
		(width 0.20066)
		(layer "F.Cu")
		(net "M_B_CPU0_SB_DQS_DP<6>")
	)
	(segment
		(start 297.899582 -217.716608)
		(end 297.40987 -217.716608)
		(width 0.20066)
		(layer "F.Cu")
		(net "M_B_CPU0_SB_DQS_DP<6>")
	)
	(segment
		(start 292.680898 -217.291666)
		(end 292.67531 -217.286078)
		(width 0.101854)
		(layer "F.Cu")
		(net "M_B_CPU0_SB_DQS_DP<6>")
	)
	(segment
		(start 297.40987 -217.716608)
		(end 297.148504 -217.977974)
		(width 0.20066)
		(layer "F.Cu")
		(net "M_B_CPU0_SB_DQS_DP<6>")
	)
	(segment
		(start 338.904834 -233.06405)
		(end 338.904834 -232.528364)
		(width 0.20066)
		(layer "F.Cu")
		(net "M_B_CPU0_SB_DQS_DP<6>")
	)
	(segment
		(start 292.922198 -217.291666)
		(end 292.680898 -217.291666)
		(width 0.101854)
		(layer "F.Cu")
		(net "M_B_CPU0_SB_DQS_DP<6>")
	)
	(segment
		(start 291.425884 -217.977974)
		(end 291.09162 -217.977974)
		(width 0.20066)
		(layer "F.Cu")
		(net "M_B_CPU0_SB_DQS_DP<6>")
	)
	(segment
		(start 290.830254 -217.716608)
		(end 290.355782 -217.716608)
		(width 0.20066)
		(layer "F.Cu")
		(net "M_B_CPU0_SB_DQS_DP<6>")
	)
	(segment
		(start 295.141904 -217.29192)
		(end 295.000426 -217.29192)
		(width 0.20066)
		(layer "F.Cu")
		(net "M_B_CPU0_SB_DQS_DP<6>")
	)
	(segment
		(start 297.148504 -217.977974)
		(end 296.543984 -217.977974)
		(width 0.20066)
		(layer "F.Cu")
		(net "M_B_CPU0_SB_DQS_DP<6>")
	)
	(segment
		(start 295.403016 -217.553032)
		(end 295.141904 -217.29192)
		(width 0.20066)
		(layer "F.Cu")
		(net "M_B_CPU0_SB_DQS_DP<6>")
	)
	(segment
		(start 292.477952 -217.286078)
		(end 292.208458 -217.555572)
		(width 0.20066)
		(layer "F.Cu")
		(net "M_B_CPU0_SB_DQS_DP<6>")
	)
	(segment
		(start 291.848286 -217.555572)
		(end 291.425884 -217.977974)
		(width 0.20066)
		(layer "F.Cu")
		(net "M_B_CPU0_SB_DQS_DP<6>")
	)
	(segment
		(start 296.543984 -217.977974)
		(end 295.907968 -217.553032)
		(width 0.20066)
		(layer "F.Cu")
		(net "M_B_CPU0_SB_DQS_DP<6>")
	)
	(segment
		(start 292.208458 -217.555572)
		(end 291.848286 -217.555572)
		(width 0.20066)
		(layer "F.Cu")
		(net "M_B_CPU0_SB_DQS_DP<6>")
	)
	(segment
		(start 307.69814 -218.203272)
		(end 307.669946 -218.231466)
		(width 0.16002)
		(layer "In2.Cu")
		(net "M_B_CPU0_SB_DQS_DP<6>")
	)
	(segment
		(start 312.014108 -217.137234)
		(end 312.014108 -217.152982)
		(width 0.16002)
		(layer "In2.Cu")
		(net "M_B_CPU0_SB_DQS_DP<6>")
	)
	(segment
		(start 304.47361 -218.727274)
		(end 304.47361 -218.711018)
		(width 0.16002)
		(layer "In2.Cu")
		(net "M_B_CPU0_SB_DQS_DP<6>")
	)
	(segment
		(start 309.814214 -217.931238)
		(end 309.677562 -217.794586)
		(width 0.18288)
		(layer "In2.Cu")
		(net "M_B_CPU0_SB_DQS_DP<6>")
	)
	(segment
		(start 304.47361 -218.711018)
		(end 304.445416 -218.682824)
		(width 0.16002)
		(layer "In2.Cu")
		(net "M_B_CPU0_SB_DQS_DP<6>")
	)
	(segment
		(start 306.054506 -219.069666)
		(end 304.832258 -219.069666)
		(width 0.18288)
		(layer "In2.Cu")
		(net "M_B_CPU0_SB_DQS_DP<6>")
	)
	(segment
		(start 302.51654 -218.203272)
		(end 302.316388 -218.00312)
		(width 0.16002)
		(layer "In2.Cu")
		(net "M_B_CPU0_SB_DQS_DP<6>")
	)
	(segment
		(start 302.288194 -217.959178)
		(end 302.109886 -217.78087)
		(width 0.18288)
		(layer "In2.Cu")
		(net "M_B_CPU0_SB_DQS_DP<6>")
	)
	(segment
		(start 313.76747 -216.944448)
		(end 312.206894 -216.944448)
		(width 0.18288)
		(layer "In2.Cu")
		(net "M_B_CPU0_SB_DQS_DP<6>")
	)
	(segment
		(start 311.798208 -217.353134)
		(end 311.770014 -217.381328)
		(width 0.16002)
		(layer "In2.Cu")
		(net "M_B_CPU0_SB_DQS_DP<6>")
	)
	(segment
		(start 310.150764 -218.267788)
		(end 310.086502 -218.203526)
		(width 0.18288)
		(layer "In2.Cu")
		(net "M_B_CPU0_SB_DQS_DP<6>")
	)
	(segment
		(start 302.316388 -218.00312)
		(end 302.316388 -217.987372)
		(width 0.16002)
		(layer "In2.Cu")
		(net "M_B_CPU0_SB_DQS_DP<6>")
	)
	(segment
		(start 332.998064 -232.03027)
		(end 332.983332 -232.038906)
		(width 0.088646)
		(layer "In2.Cu")
		(net "M_B_CPU0_SB_DQS_DP<6>")
	)
	(segment
		(start 311.813956 -217.353134)
		(end 311.798208 -217.353134)
		(width 0.16002)
		(layer "In2.Cu")
		(net "M_B_CPU0_SB_DQS_DP<6>")
	)
	(segment
		(start 300.421294 -217.921078)
		(end 300.3931 -217.949272)
		(width 0.16002)
		(layer "In2.Cu")
		(net "M_B_CPU0_SB_DQS_DP<6>")
	)
	(segment
		(start 304.68951 -218.926918)
		(end 304.673254 -218.926918)
		(width 0.16002)
		(layer "In2.Cu")
		(net "M_B_CPU0_SB_DQS_DP<6>")
	)
	(segment
		(start 307.505862 -218.39555)
		(end 306.728622 -218.39555)
		(width 0.18288)
		(layer "In2.Cu")
		(net "M_B_CPU0_SB_DQS_DP<6>")
	)
	(segment
		(start 338.59216 -232.528364)
		(end 338.526374 -232.462578)
		(width 0.088646)
		(layer "In2.Cu")
		(net "M_B_CPU0_SB_DQS_DP<6>")
	)
	(segment
		(start 300.149006 -218.193366)
		(end 300.078902 -218.26347)
		(width 0.18288)
		(layer "In2.Cu")
		(net "M_B_CPU0_SB_DQS_DP<6>")
	)
	(segment
		(start 310.058308 -218.175332)
		(end 310.04256 -218.175332)
		(width 0.16002)
		(layer "In2.Cu")
		(net "M_B_CPU0_SB_DQS_DP<6>")
	)
	(segment
		(start 312.014108 -217.152982)
		(end 311.813956 -217.353134)
		(width 0.16002)
		(layer "In2.Cu")
		(net "M_B_CPU0_SB_DQS_DP<6>")
	)
	(segment
		(start 313.960256 -217.152982)
		(end 313.960256 -217.137234)
		(width 0.16002)
		(layer "In2.Cu")
		(net "M_B_CPU0_SB_DQS_DP<6>")
	)
	(segment
		(start 306.413154 -218.711018)
		(end 306.413154 -218.727274)
		(width 0.16002)
		(layer "In2.Cu")
		(net "M_B_CPU0_SB_DQS_DP<6>")
	)
	(segment
		(start 314.176156 -217.353134)
		(end 314.160408 -217.353134)
		(width 0.16002)
		(layer "In2.Cu")
		(net "M_B_CPU0_SB_DQS_DP<6>")
	)
	(segment
		(start 314.160408 -217.353134)
		(end 313.960256 -217.152982)
		(width 0.16002)
		(layer "In2.Cu")
		(net "M_B_CPU0_SB_DQS_DP<6>")
	)
	(segment
		(start 302.316388 -217.987372)
		(end 302.288194 -217.959178)
		(width 0.16002)
		(layer "In2.Cu")
		(net "M_B_CPU0_SB_DQS_DP<6>")
	)
	(segment
		(start 304.445416 -218.682824)
		(end 304.107342 -218.34475)
		(width 0.18288)
		(layer "In2.Cu")
		(net "M_B_CPU0_SB_DQS_DP<6>")
	)
	(segment
		(start 306.441348 -218.682824)
		(end 306.413154 -218.711018)
		(width 0.16002)
		(layer "In2.Cu")
		(net "M_B_CPU0_SB_DQS_DP<6>")
	)
	(segment
		(start 309.842408 -217.959432)
		(end 309.814214 -217.931238)
		(width 0.16002)
		(layer "In2.Cu")
		(net "M_B_CPU0_SB_DQS_DP<6>")
	)
	(segment
		(start 304.107342 -218.34475)
		(end 302.673766 -218.34475)
		(width 0.18288)
		(layer "In2.Cu")
		(net "M_B_CPU0_SB_DQS_DP<6>")
	)
	(segment
		(start 309.842408 -217.97518)
		(end 309.842408 -217.959432)
		(width 0.16002)
		(layer "In2.Cu")
		(net "M_B_CPU0_SB_DQS_DP<6>")
	)
	(segment
		(start 299.268896 -217.981022)
		(end 299.004482 -217.716608)
		(width 0.18288)
		(layer "In2.Cu")
		(net "M_B_CPU0_SB_DQS_DP<6>")
	)
	(segment
		(start 308.106826 -217.794586)
		(end 307.942234 -217.959178)
		(width 0.18288)
		(layer "In2.Cu")
		(net "M_B_CPU0_SB_DQS_DP<6>")
	)
	(segment
		(start 300.561502 -217.78087)
		(end 300.421294 -217.921078)
		(width 0.18288)
		(layer "In2.Cu")
		(net "M_B_CPU0_SB_DQS_DP<6>")
	)
	(segment
		(start 306.16906 -218.955112)
		(end 306.054506 -219.069666)
		(width 0.18288)
		(layer "In2.Cu")
		(net "M_B_CPU0_SB_DQS_DP<6>")
	)
	(segment
		(start 310.04256 -218.175332)
		(end 309.842408 -217.97518)
		(width 0.16002)
		(layer "In2.Cu")
		(net "M_B_CPU0_SB_DQS_DP<6>")
	)
	(segment
		(start 337.307682 -232.038906)
		(end 337.29295 -232.03027)
		(width 0.088646)
		(layer "In2.Cu")
		(net "M_B_CPU0_SB_DQS_DP<6>")
	)
	(segment
		(start 312.042302 -217.10904)
		(end 312.014108 -217.137234)
		(width 0.16002)
		(layer "In2.Cu")
		(net "M_B_CPU0_SB_DQS_DP<6>")
	)
	(segment
		(start 311.770014 -217.381328)
		(end 311.558686 -217.592656)
		(width 0.18288)
		(layer "In2.Cu")
		(net "M_B_CPU0_SB_DQS_DP<6>")
	)
	(segment
		(start 332.017878 -231.96296)
		(end 331.783944 -231.728264)
		(width 0.088646)
		(layer "In2.Cu")
		(net "M_B_CPU0_SB_DQS_DP<6>")
	)
	(segment
		(start 336.367882 -232.038906)
		(end 336.357468 -232.03281)
		(width 0.088646)
		(layer "In2.Cu")
		(net "M_B_CPU0_SB_DQS_DP<6>")
	)
	(segment
		(start 307.91404 -218.00312)
		(end 307.713888 -218.203272)
		(width 0.16002)
		(layer "In2.Cu")
		(net "M_B_CPU0_SB_DQS_DP<6>")
	)
	(segment
		(start 300.1772 -218.165172)
		(end 300.149006 -218.193366)
		(width 0.16002)
		(layer "In2.Cu")
		(net "M_B_CPU0_SB_DQS_DP<6>")
	)
	(segment
		(start 314.20435 -217.381328)
		(end 314.176156 -217.353134)
		(width 0.16002)
		(layer "In2.Cu")
		(net "M_B_CPU0_SB_DQS_DP<6>")
	)
	(segment
		(start 313.932062 -217.10904)
		(end 313.76747 -216.944448)
		(width 0.18288)
		(layer "In2.Cu")
		(net "M_B_CPU0_SB_DQS_DP<6>")
	)
	(segment
		(start 304.673254 -218.926918)
		(end 304.47361 -218.727274)
		(width 0.16002)
		(layer "In2.Cu")
		(net "M_B_CPU0_SB_DQS_DP<6>")
	)
	(segment
		(start 302.560482 -218.231466)
		(end 302.532288 -218.203272)
		(width 0.16002)
		(layer "In2.Cu")
		(net "M_B_CPU0_SB_DQS_DP<6>")
	)
	(segment
		(start 326.436736 -226.113594)
		(end 317.75273 -217.429588)
		(width 0.18288)
		(layer "In2.Cu")
		(net "M_B_CPU0_SB_DQS_DP<6>")
	)
	(segment
		(start 326.436736 -226.296982)
		(end 326.436736 -226.113594)
		(width 0.18288)
		(layer "In2.Cu")
		(net "M_B_CPU0_SB_DQS_DP<6>")
	)
	(segment
		(start 302.109886 -217.78087)
		(end 300.561502 -217.78087)
		(width 0.18288)
		(layer "In2.Cu")
		(net "M_B_CPU0_SB_DQS_DP<6>")
	)
	(segment
		(start 299.885608 -218.26347)
		(end 299.60316 -217.981022)
		(width 0.18288)
		(layer "In2.Cu")
		(net "M_B_CPU0_SB_DQS_DP<6>")
	)
	(segment
		(start 311.10301 -217.592656)
		(end 310.427878 -218.267788)
		(width 0.18288)
		(layer "In2.Cu")
		(net "M_B_CPU0_SB_DQS_DP<6>")
	)
	(segment
		(start 302.673766 -218.34475)
		(end 302.560482 -218.231466)
		(width 0.18288)
		(layer "In2.Cu")
		(net "M_B_CPU0_SB_DQS_DP<6>")
	)
	(segment
		(start 302.532288 -218.203272)
		(end 302.51654 -218.203272)
		(width 0.16002)
		(layer "In2.Cu")
		(net "M_B_CPU0_SB_DQS_DP<6>")
	)
	(segment
		(start 307.713888 -218.203272)
		(end 307.69814 -218.203272)
		(width 0.16002)
		(layer "In2.Cu")
		(net "M_B_CPU0_SB_DQS_DP<6>")
	)
	(segment
		(start 306.21351 -218.926918)
		(end 306.197254 -218.926918)
		(width 0.16002)
		(layer "In2.Cu")
		(net "M_B_CPU0_SB_DQS_DP<6>")
	)
	(segment
		(start 332.608936 -232.038906)
		(end 332.608682 -232.039414)
		(width 0.088646)
		(layer "In2.Cu")
		(net "M_B_CPU0_SB_DQS_DP<6>")
	)
	(segment
		(start 310.427878 -218.267788)
		(end 310.150764 -218.267788)
		(width 0.18288)
		(layer "In2.Cu")
		(net "M_B_CPU0_SB_DQS_DP<6>")
	)
	(segment
		(start 307.669946 -218.231466)
		(end 307.505862 -218.39555)
		(width 0.18288)
		(layer "In2.Cu")
		(net "M_B_CPU0_SB_DQS_DP<6>")
	)
	(segment
		(start 300.192948 -218.165172)
		(end 300.1772 -218.165172)
		(width 0.16002)
		(layer "In2.Cu")
		(net "M_B_CPU0_SB_DQS_DP<6>")
	)
	(segment
		(start 332.326488 -231.96296)
		(end 332.017878 -231.96296)
		(width 0.088646)
		(layer "In2.Cu")
		(net "M_B_CPU0_SB_DQS_DP<6>")
	)
	(segment
		(start 306.197254 -218.926918)
		(end 306.16906 -218.955112)
		(width 0.16002)
		(layer "In2.Cu")
		(net "M_B_CPU0_SB_DQS_DP<6>")
	)
	(segment
		(start 300.078902 -218.26347)
		(end 299.885608 -218.26347)
		(width 0.18288)
		(layer "In2.Cu")
		(net "M_B_CPU0_SB_DQS_DP<6>")
	)
	(segment
		(start 304.832258 -219.069666)
		(end 304.717704 -218.955112)
		(width 0.18288)
		(layer "In2.Cu")
		(net "M_B_CPU0_SB_DQS_DP<6>")
	)
	(segment
		(start 317.75273 -217.429588)
		(end 314.25261 -217.429588)
		(width 0.18288)
		(layer "In2.Cu")
		(net "M_B_CPU0_SB_DQS_DP<6>")
	)
	(segment
		(start 312.206894 -216.944448)
		(end 312.042302 -217.10904)
		(width 0.18288)
		(layer "In2.Cu")
		(net "M_B_CPU0_SB_DQS_DP<6>")
	)
	(segment
		(start 338.904834 -232.528364)
		(end 338.59216 -232.528364)
		(width 0.088646)
		(layer "In2.Cu")
		(net "M_B_CPU0_SB_DQS_DP<6>")
	)
	(segment
		(start 310.086502 -218.203526)
		(end 310.058308 -218.175332)
		(width 0.16002)
		(layer "In2.Cu")
		(net "M_B_CPU0_SB_DQS_DP<6>")
	)
	(segment
		(start 331.784198 -231.644444)
		(end 326.436736 -226.296982)
		(width 0.18288)
		(layer "In2.Cu")
		(net "M_B_CPU0_SB_DQS_DP<6>")
	)
	(segment
		(start 299.60316 -217.981022)
		(end 299.268896 -217.981022)
		(width 0.18288)
		(layer "In2.Cu")
		(net "M_B_CPU0_SB_DQS_DP<6>")
	)
	(segment
		(start 309.677562 -217.794586)
		(end 308.106826 -217.794586)
		(width 0.18288)
		(layer "In2.Cu")
		(net "M_B_CPU0_SB_DQS_DP<6>")
	)
	(segment
		(start 307.942234 -217.959178)
		(end 307.91404 -217.987372)
		(width 0.16002)
		(layer "In2.Cu")
		(net "M_B_CPU0_SB_DQS_DP<6>")
	)
	(segment
		(start 306.728622 -218.39555)
		(end 306.441348 -218.682824)
		(width 0.18288)
		(layer "In2.Cu")
		(net "M_B_CPU0_SB_DQS_DP<6>")
	)
	(segment
		(start 306.413154 -218.727274)
		(end 306.21351 -218.926918)
		(width 0.16002)
		(layer "In2.Cu")
		(net "M_B_CPU0_SB_DQS_DP<6>")
	)
	(segment
		(start 300.3931 -217.96502)
		(end 300.192948 -218.165172)
		(width 0.16002)
		(layer "In2.Cu")
		(net "M_B_CPU0_SB_DQS_DP<6>")
	)
	(segment
		(start 307.91404 -217.987372)
		(end 307.91404 -218.00312)
		(width 0.16002)
		(layer "In2.Cu")
		(net "M_B_CPU0_SB_DQS_DP<6>")
	)
	(segment
		(start 300.3931 -217.949272)
		(end 300.3931 -217.96502)
		(width 0.16002)
		(layer "In2.Cu")
		(net "M_B_CPU0_SB_DQS_DP<6>")
	)
	(segment
		(start 304.717704 -218.955112)
		(end 304.68951 -218.926918)
		(width 0.16002)
		(layer "In2.Cu")
		(net "M_B_CPU0_SB_DQS_DP<6>")
	)
	(segment
		(start 314.25261 -217.429588)
		(end 314.20435 -217.381328)
		(width 0.18288)
		(layer "In2.Cu")
		(net "M_B_CPU0_SB_DQS_DP<6>")
	)
	(segment
		(start 331.783944 -231.728264)
		(end 331.784198 -231.644444)
		(width 0.088646)
		(layer "In2.Cu")
		(net "M_B_CPU0_SB_DQS_DP<6>")
	)
	(segment
		(start 313.960256 -217.137234)
		(end 313.932062 -217.10904)
		(width 0.16002)
		(layer "In2.Cu")
		(net "M_B_CPU0_SB_DQS_DP<6>")
	)
	(segment
		(start 311.558686 -217.592656)
		(end 311.10301 -217.592656)
		(width 0.18288)
		(layer "In2.Cu")
		(net "M_B_CPU0_SB_DQS_DP<6>")
	)
	(arc
		(start 336.742278 -232.038906)
		(mid 336.55508 -232.089049)
		(end 336.367882 -232.038906)
		(width 0.088646)
		(layer "In2.Cu")
		(net "M_B_CPU0_SB_DQS_DP<6>")
	)
	(arc
		(start 338.526374 -232.462578)
		(mid 338.525073 -232.452151)
		(end 338.52358 -232.44175)
		(width 0.088646)
		(layer "In2.Cu")
		(net "M_B_CPU0_SB_DQS_DP<6>")
	)
	(arc
		(start 334.862932 -232.038906)
		(mid 334.675734 -232.089049)
		(end 334.488536 -232.038906)
		(width 0.088646)
		(layer "In2.Cu")
		(net "M_B_CPU0_SB_DQS_DP<6>")
	)
	(arc
		(start 333.548736 -232.038906)
		(mid 333.274537 -231.963071)
		(end 332.998064 -232.03027)
		(width 0.088646)
		(layer "In2.Cu")
		(net "M_B_CPU0_SB_DQS_DP<6>")
	)
	(arc
		(start 338.52358 -232.44175)
		(mid 338.20905 -232.018529)
		(end 337.682078 -232.038906)
		(width 0.088646)
		(layer "In2.Cu")
		(net "M_B_CPU0_SB_DQS_DP<6>")
	)
	(arc
		(start 333.923132 -232.038906)
		(mid 333.735934 -232.089049)
		(end 333.548736 -232.038906)
		(width 0.088646)
		(layer "In2.Cu")
		(net "M_B_CPU0_SB_DQS_DP<6>")
	)
	(arc
		(start 336.357468 -232.03281)
		(mid 336.07929 -231.963087)
		(end 335.802732 -232.038906)
		(width 0.088646)
		(layer "In2.Cu")
		(net "M_B_CPU0_SB_DQS_DP<6>")
	)
	(arc
		(start 335.428336 -232.038906)
		(mid 335.145634 -231.96313)
		(end 334.862932 -232.038906)
		(width 0.088646)
		(layer "In2.Cu")
		(net "M_B_CPU0_SB_DQS_DP<6>")
	)
	(arc
		(start 334.488536 -232.038906)
		(mid 334.205834 -231.96313)
		(end 333.923132 -232.038906)
		(width 0.088646)
		(layer "In2.Cu")
		(net "M_B_CPU0_SB_DQS_DP<6>")
	)
	(arc
		(start 332.608682 -232.039414)
		(mid 332.47261 -231.982656)
		(end 332.326488 -231.96296)
		(width 0.088646)
		(layer "In2.Cu")
		(net "M_B_CPU0_SB_DQS_DP<6>")
	)
	(arc
		(start 337.682078 -232.038906)
		(mid 337.49488 -232.089049)
		(end 337.307682 -232.038906)
		(width 0.088646)
		(layer "In2.Cu")
		(net "M_B_CPU0_SB_DQS_DP<6>")
	)
	(arc
		(start 332.983332 -232.038906)
		(mid 332.796134 -232.089049)
		(end 332.608936 -232.038906)
		(width 0.088646)
		(layer "In2.Cu")
		(net "M_B_CPU0_SB_DQS_DP<6>")
	)
	(arc
		(start 335.802732 -232.038906)
		(mid 335.615534 -232.089049)
		(end 335.428336 -232.038906)
		(width 0.088646)
		(layer "In2.Cu")
		(net "M_B_CPU0_SB_DQS_DP<6>")
	)
	(arc
		(start 337.29295 -232.03027)
		(mid 337.016475 -231.96295)
		(end 336.742278 -232.038906)
		(width 0.088646)
		(layer "In2.Cu")
		(net "M_B_CPU0_SB_DQS_DP<6>")
	)
	(segment
		(start 291.09162 -227.327968)
		(end 290.830254 -227.066602)
		(width 0.20066)
		(layer "F.Cu")
		(net "M_B_CPU0_SB_DQS_DP<5>")
	)
	(segment
		(start 292.922198 -226.64166)
		(end 292.680898 -226.64166)
		(width 0.101854)
		(layer "F.Cu")
		(net "M_B_CPU0_SB_DQS_DP<5>")
	)
	(segment
		(start 342.194134 -235.506006)
		(end 342.194134 -234.97032)
		(width 0.20066)
		(layer "F.Cu")
		(net "M_B_CPU0_SB_DQS_DP<5>")
	)
	(segment
		(start 342.194134 -234.97032)
		(end 342.19388 -234.970066)
		(width 0.20066)
		(layer "F.Cu")
		(net "M_B_CPU0_SB_DQS_DP<5>")
	)
	(segment
		(start 295.000172 -226.64166)
		(end 292.922198 -226.64166)
		(width 0.1016)
		(layer "F.Cu")
		(net "M_B_CPU0_SB_DQS_DP<5>")
	)
	(segment
		(start 291.848286 -226.905566)
		(end 291.425884 -227.327968)
		(width 0.20066)
		(layer "F.Cu")
		(net "M_B_CPU0_SB_DQS_DP<5>")
	)
	(segment
		(start 295.403016 -226.903026)
		(end 295.141904 -226.641914)
		(width 0.20066)
		(layer "F.Cu")
		(net "M_B_CPU0_SB_DQS_DP<5>")
	)
	(segment
		(start 295.907968 -226.903026)
		(end 295.403016 -226.903026)
		(width 0.20066)
		(layer "F.Cu")
		(net "M_B_CPU0_SB_DQS_DP<5>")
	)
	(segment
		(start 292.680898 -226.64166)
		(end 292.67531 -226.636072)
		(width 0.101854)
		(layer "F.Cu")
		(net "M_B_CPU0_SB_DQS_DP<5>")
	)
	(segment
		(start 292.208458 -226.905566)
		(end 291.848286 -226.905566)
		(width 0.20066)
		(layer "F.Cu")
		(net "M_B_CPU0_SB_DQS_DP<5>")
	)
	(segment
		(start 297.899582 -227.066602)
		(end 297.40987 -227.066602)
		(width 0.20066)
		(layer "F.Cu")
		(net "M_B_CPU0_SB_DQS_DP<5>")
	)
	(segment
		(start 297.148504 -227.327968)
		(end 296.543984 -227.327968)
		(width 0.20066)
		(layer "F.Cu")
		(net "M_B_CPU0_SB_DQS_DP<5>")
	)
	(segment
		(start 295.141904 -226.641914)
		(end 295.000426 -226.641914)
		(width 0.20066)
		(layer "F.Cu")
		(net "M_B_CPU0_SB_DQS_DP<5>")
	)
	(segment
		(start 297.40987 -227.066602)
		(end 297.148504 -227.327968)
		(width 0.20066)
		(layer "F.Cu")
		(net "M_B_CPU0_SB_DQS_DP<5>")
	)
	(segment
		(start 292.477952 -226.636072)
		(end 292.208458 -226.905566)
		(width 0.20066)
		(layer "F.Cu")
		(net "M_B_CPU0_SB_DQS_DP<5>")
	)
	(segment
		(start 299.004482 -227.066602)
		(end 297.899582 -227.066602)
		(width 0.20066)
		(layer "F.Cu")
		(net "M_B_CPU0_SB_DQS_DP<5>")
	)
	(segment
		(start 295.000426 -226.641914)
		(end 295.000172 -226.64166)
		(width 0.1016)
		(layer "F.Cu")
		(net "M_B_CPU0_SB_DQS_DP<5>")
	)
	(segment
		(start 291.425884 -227.327968)
		(end 291.09162 -227.327968)
		(width 0.20066)
		(layer "F.Cu")
		(net "M_B_CPU0_SB_DQS_DP<5>")
	)
	(segment
		(start 290.830254 -227.066602)
		(end 290.355782 -227.066602)
		(width 0.20066)
		(layer "F.Cu")
		(net "M_B_CPU0_SB_DQS_DP<5>")
	)
	(segment
		(start 292.67531 -226.636072)
		(end 292.477952 -226.636072)
		(width 0.20066)
		(layer "F.Cu")
		(net "M_B_CPU0_SB_DQS_DP<5>")
	)
	(segment
		(start 296.543984 -227.327968)
		(end 295.907968 -226.903026)
		(width 0.20066)
		(layer "F.Cu")
		(net "M_B_CPU0_SB_DQS_DP<5>")
	)
	(segment
		(start 340.986364 -234.471972)
		(end 340.971632 -234.480608)
		(width 0.088646)
		(layer "In4.Cu")
		(net "M_B_CPU0_SB_DQS_DP<5>")
	)
	(segment
		(start 299.452538 -227.514658)
		(end 299.004482 -227.066602)
		(width 0.18288)
		(layer "In4.Cu")
		(net "M_B_CPU0_SB_DQS_DP<5>")
	)
	(segment
		(start 310.184546 -224.941638)
		(end 309.79618 -224.941638)
		(width 0.18288)
		(layer "In4.Cu")
		(net "M_B_CPU0_SB_DQS_DP<5>")
	)
	(segment
		(start 308.937152 -225.213672)
		(end 308.294278 -224.570798)
		(width 0.18288)
		(layer "In4.Cu")
		(net "M_B_CPU0_SB_DQS_DP<5>")
	)
	(segment
		(start 314.57265 -226.941888)
		(end 314.27547 -226.644708)
		(width 0.18288)
		(layer "In4.Cu")
		(net "M_B_CPU0_SB_DQS_DP<5>")
	)
	(segment
		(start 336.287364 -234.471972)
		(end 336.272632 -234.480608)
		(width 0.088646)
		(layer "In4.Cu")
		(net "M_B_CPU0_SB_DQS_DP<5>")
	)
	(segment
		(start 309.527702 -225.210116)
		(end 309.522114 -225.210116)
		(width 0.18288)
		(layer "In4.Cu")
		(net "M_B_CPU0_SB_DQS_DP<5>")
	)
	(segment
		(start 309.518558 -225.213672)
		(end 308.937152 -225.213672)
		(width 0.18288)
		(layer "In4.Cu")
		(net "M_B_CPU0_SB_DQS_DP<5>")
	)
	(segment
		(start 308.294278 -224.570798)
		(end 307.255926 -224.570798)
		(width 0.18288)
		(layer "In4.Cu")
		(net "M_B_CPU0_SB_DQS_DP<5>")
	)
	(segment
		(start 337.227164 -234.471972)
		(end 337.212432 -234.480608)
		(width 0.088646)
		(layer "In4.Cu")
		(net "M_B_CPU0_SB_DQS_DP<5>")
	)
	(segment
		(start 301.726854 -226.311206)
		(end 300.523402 -227.514658)
		(width 0.18288)
		(layer "In4.Cu")
		(net "M_B_CPU0_SB_DQS_DP<5>")
	)
	(segment
		(start 304.540412 -226.699318)
		(end 304.122582 -226.699318)
		(width 0.18288)
		(layer "In4.Cu")
		(net "M_B_CPU0_SB_DQS_DP<5>")
	)
	(segment
		(start 313.109102 -226.923854)
		(end 312.833258 -226.64801)
		(width 0.18288)
		(layer "In4.Cu")
		(net "M_B_CPU0_SB_DQS_DP<5>")
	)
	(segment
		(start 339.106764 -234.471972)
		(end 339.092032 -234.480608)
		(width 0.088646)
		(layer "In4.Cu")
		(net "M_B_CPU0_SB_DQS_DP<5>")
	)
	(segment
		(start 342.19388 -234.970066)
		(end 341.881206 -234.970066)
		(width 0.088646)
		(layer "In4.Cu")
		(net "M_B_CPU0_SB_DQS_DP<5>")
	)
	(segment
		(start 332.326234 -234.531154)
		(end 331.691234 -234.531154)
		(width 0.088646)
		(layer "In4.Cu")
		(net "M_B_CPU0_SB_DQS_DP<5>")
	)
	(segment
		(start 309.79618 -224.941638)
		(end 309.527702 -225.210116)
		(width 0.18288)
		(layer "In4.Cu")
		(net "M_B_CPU0_SB_DQS_DP<5>")
	)
	(segment
		(start 314.27547 -226.644708)
		(end 313.89701 -226.644708)
		(width 0.18288)
		(layer "In4.Cu")
		(net "M_B_CPU0_SB_DQS_DP<5>")
	)
	(segment
		(start 333.467964 -234.471972)
		(end 333.453232 -234.480608)
		(width 0.088646)
		(layer "In4.Cu")
		(net "M_B_CPU0_SB_DQS_DP<5>")
	)
	(segment
		(start 300.523402 -227.514658)
		(end 299.452538 -227.514658)
		(width 0.18288)
		(layer "In4.Cu")
		(net "M_B_CPU0_SB_DQS_DP<5>")
	)
	(segment
		(start 313.89701 -226.644708)
		(end 313.617864 -226.923854)
		(width 0.18288)
		(layer "In4.Cu")
		(net "M_B_CPU0_SB_DQS_DP<5>")
	)
	(segment
		(start 323.086222 -234.42295)
		(end 315.60516 -226.941888)
		(width 0.18288)
		(layer "In4.Cu")
		(net "M_B_CPU0_SB_DQS_DP<5>")
	)
	(segment
		(start 306.621434 -225.20529)
		(end 306.03444 -225.20529)
		(width 0.18288)
		(layer "In4.Cu")
		(net "M_B_CPU0_SB_DQS_DP<5>")
	)
	(segment
		(start 312.833258 -226.64801)
		(end 312.833258 -226.051872)
		(width 0.18288)
		(layer "In4.Cu")
		(net "M_B_CPU0_SB_DQS_DP<5>")
	)
	(segment
		(start 330.648564 -234.42295)
		(end 323.086222 -234.42295)
		(width 0.18288)
		(layer "In4.Cu")
		(net "M_B_CPU0_SB_DQS_DP<5>")
	)
	(segment
		(start 330.693014 -234.42295)
		(end 330.648564 -234.42295)
		(width 0.088646)
		(layer "In4.Cu")
		(net "M_B_CPU0_SB_DQS_DP<5>")
	)
	(segment
		(start 331.691234 -234.531154)
		(end 331.55509 -234.667298)
		(width 0.088646)
		(layer "In4.Cu")
		(net "M_B_CPU0_SB_DQS_DP<5>")
	)
	(segment
		(start 310.45531 -225.212402)
		(end 310.184546 -224.941638)
		(width 0.18288)
		(layer "In4.Cu")
		(net "M_B_CPU0_SB_DQS_DP<5>")
	)
	(segment
		(start 335.347564 -234.471972)
		(end 335.332832 -234.480608)
		(width 0.088646)
		(layer "In4.Cu")
		(net "M_B_CPU0_SB_DQS_DP<5>")
	)
	(segment
		(start 341.881206 -234.970066)
		(end 341.815674 -234.904534)
		(width 0.088646)
		(layer "In4.Cu")
		(net "M_B_CPU0_SB_DQS_DP<5>")
	)
	(segment
		(start 307.255926 -224.570798)
		(end 306.621434 -225.20529)
		(width 0.18288)
		(layer "In4.Cu")
		(net "M_B_CPU0_SB_DQS_DP<5>")
	)
	(segment
		(start 309.522114 -225.210116)
		(end 309.518558 -225.213672)
		(width 0.18288)
		(layer "In4.Cu")
		(net "M_B_CPU0_SB_DQS_DP<5>")
	)
	(segment
		(start 331.103986 -234.48264)
		(end 330.752704 -234.48264)
		(width 0.088646)
		(layer "In4.Cu")
		(net "M_B_CPU0_SB_DQS_DP<5>")
	)
	(segment
		(start 330.752704 -234.48264)
		(end 330.693014 -234.42295)
		(width 0.088646)
		(layer "In4.Cu")
		(net "M_B_CPU0_SB_DQS_DP<5>")
	)
	(segment
		(start 313.617864 -226.923854)
		(end 313.109102 -226.923854)
		(width 0.18288)
		(layer "In4.Cu")
		(net "M_B_CPU0_SB_DQS_DP<5>")
	)
	(segment
		(start 306.03444 -225.20529)
		(end 304.540412 -226.699318)
		(width 0.18288)
		(layer "In4.Cu")
		(net "M_B_CPU0_SB_DQS_DP<5>")
	)
	(segment
		(start 311.993788 -225.212402)
		(end 310.45531 -225.212402)
		(width 0.18288)
		(layer "In4.Cu")
		(net "M_B_CPU0_SB_DQS_DP<5>")
	)
	(segment
		(start 312.833258 -226.051872)
		(end 311.993788 -225.212402)
		(width 0.18288)
		(layer "In4.Cu")
		(net "M_B_CPU0_SB_DQS_DP<5>")
	)
	(segment
		(start 340.046564 -234.471972)
		(end 340.031832 -234.480608)
		(width 0.088646)
		(layer "In4.Cu")
		(net "M_B_CPU0_SB_DQS_DP<5>")
	)
	(segment
		(start 331.55509 -234.667298)
		(end 331.288644 -234.667298)
		(width 0.088646)
		(layer "In4.Cu")
		(net "M_B_CPU0_SB_DQS_DP<5>")
	)
	(segment
		(start 334.407764 -234.471972)
		(end 334.393032 -234.480608)
		(width 0.088646)
		(layer "In4.Cu")
		(net "M_B_CPU0_SB_DQS_DP<5>")
	)
	(segment
		(start 304.122582 -226.699318)
		(end 303.73447 -226.311206)
		(width 0.18288)
		(layer "In4.Cu")
		(net "M_B_CPU0_SB_DQS_DP<5>")
	)
	(segment
		(start 331.288644 -234.667298)
		(end 331.103986 -234.48264)
		(width 0.088646)
		(layer "In4.Cu")
		(net "M_B_CPU0_SB_DQS_DP<5>")
	)
	(segment
		(start 315.60516 -226.941888)
		(end 314.57265 -226.941888)
		(width 0.18288)
		(layer "In4.Cu")
		(net "M_B_CPU0_SB_DQS_DP<5>")
	)
	(segment
		(start 303.73447 -226.311206)
		(end 301.726854 -226.311206)
		(width 0.18288)
		(layer "In4.Cu")
		(net "M_B_CPU0_SB_DQS_DP<5>")
	)
	(arc
		(start 338.152232 -234.480608)
		(mid 337.965034 -234.530751)
		(end 337.777836 -234.480608)
		(width 0.088646)
		(layer "In4.Cu")
		(net "M_B_CPU0_SB_DQS_DP<5>")
	)
	(arc
		(start 336.838036 -234.480608)
		(mid 336.563837 -234.404773)
		(end 336.287364 -234.471972)
		(width 0.088646)
		(layer "In4.Cu")
		(net "M_B_CPU0_SB_DQS_DP<5>")
	)
	(arc
		(start 332.513686 -234.480862)
		(mid 332.423267 -234.518321)
		(end 332.326234 -234.531154)
		(width 0.088646)
		(layer "In4.Cu")
		(net "M_B_CPU0_SB_DQS_DP<5>")
	)
	(arc
		(start 337.777836 -234.480608)
		(mid 337.503637 -234.404773)
		(end 337.227164 -234.471972)
		(width 0.088646)
		(layer "In4.Cu")
		(net "M_B_CPU0_SB_DQS_DP<5>")
	)
	(arc
		(start 335.332832 -234.480608)
		(mid 335.145634 -234.530751)
		(end 334.958436 -234.480608)
		(width 0.088646)
		(layer "In4.Cu")
		(net "M_B_CPU0_SB_DQS_DP<5>")
	)
	(arc
		(start 333.078836 -234.480608)
		(mid 332.804637 -234.404773)
		(end 332.528164 -234.471972)
		(width 0.088646)
		(layer "In4.Cu")
		(net "M_B_CPU0_SB_DQS_DP<5>")
	)
	(arc
		(start 340.971632 -234.480608)
		(mid 340.784434 -234.530751)
		(end 340.597236 -234.480608)
		(width 0.088646)
		(layer "In4.Cu")
		(net "M_B_CPU0_SB_DQS_DP<5>")
	)
	(arc
		(start 340.597236 -234.480608)
		(mid 340.323037 -234.404773)
		(end 340.046564 -234.471972)
		(width 0.088646)
		(layer "In4.Cu")
		(net "M_B_CPU0_SB_DQS_DP<5>")
	)
	(arc
		(start 341.815674 -234.904534)
		(mid 341.814376 -234.89398)
		(end 341.81288 -234.883452)
		(width 0.088646)
		(layer "In4.Cu")
		(net "M_B_CPU0_SB_DQS_DP<5>")
	)
	(arc
		(start 332.528164 -234.471972)
		(mid 332.520976 -234.4765)
		(end 332.513686 -234.480862)
		(width 0.088646)
		(layer "In4.Cu")
		(net "M_B_CPU0_SB_DQS_DP<5>")
	)
	(arc
		(start 339.657436 -234.480608)
		(mid 339.383237 -234.404773)
		(end 339.106764 -234.471972)
		(width 0.088646)
		(layer "In4.Cu")
		(net "M_B_CPU0_SB_DQS_DP<5>")
	)
	(arc
		(start 337.212432 -234.480608)
		(mid 337.025234 -234.530751)
		(end 336.838036 -234.480608)
		(width 0.088646)
		(layer "In4.Cu")
		(net "M_B_CPU0_SB_DQS_DP<5>")
	)
	(arc
		(start 336.272632 -234.480608)
		(mid 336.085434 -234.530751)
		(end 335.898236 -234.480608)
		(width 0.088646)
		(layer "In4.Cu")
		(net "M_B_CPU0_SB_DQS_DP<5>")
	)
	(arc
		(start 333.453232 -234.480608)
		(mid 333.266034 -234.530751)
		(end 333.078836 -234.480608)
		(width 0.088646)
		(layer "In4.Cu")
		(net "M_B_CPU0_SB_DQS_DP<5>")
	)
	(arc
		(start 339.092032 -234.480608)
		(mid 338.904834 -234.530751)
		(end 338.717636 -234.480608)
		(width 0.088646)
		(layer "In4.Cu")
		(net "M_B_CPU0_SB_DQS_DP<5>")
	)
	(arc
		(start 334.393032 -234.480608)
		(mid 334.205834 -234.530751)
		(end 334.018636 -234.480608)
		(width 0.088646)
		(layer "In4.Cu")
		(net "M_B_CPU0_SB_DQS_DP<5>")
	)
	(arc
		(start 334.958436 -234.480608)
		(mid 334.684237 -234.404773)
		(end 334.407764 -234.471972)
		(width 0.088646)
		(layer "In4.Cu")
		(net "M_B_CPU0_SB_DQS_DP<5>")
	)
	(arc
		(start 341.81288 -234.883452)
		(mid 341.506093 -234.463856)
		(end 340.986364 -234.471972)
		(width 0.088646)
		(layer "In4.Cu")
		(net "M_B_CPU0_SB_DQS_DP<5>")
	)
	(arc
		(start 334.018636 -234.480608)
		(mid 333.744437 -234.404773)
		(end 333.467964 -234.471972)
		(width 0.088646)
		(layer "In4.Cu")
		(net "M_B_CPU0_SB_DQS_DP<5>")
	)
	(arc
		(start 340.031832 -234.480608)
		(mid 339.844634 -234.530751)
		(end 339.657436 -234.480608)
		(width 0.088646)
		(layer "In4.Cu")
		(net "M_B_CPU0_SB_DQS_DP<5>")
	)
	(arc
		(start 335.898236 -234.480608)
		(mid 335.624037 -234.404773)
		(end 335.347564 -234.471972)
		(width 0.088646)
		(layer "In4.Cu")
		(net "M_B_CPU0_SB_DQS_DP<5>")
	)
	(arc
		(start 338.717636 -234.480608)
		(mid 338.434934 -234.404832)
		(end 338.152232 -234.480608)
		(width 0.088646)
		(layer "In4.Cu")
		(net "M_B_CPU0_SB_DQS_DP<5>")
	)
	(segment
		(start 297.40987 -236.416596)
		(end 297.148504 -236.677962)
		(width 0.20066)
		(layer "F.Cu")
		(net "M_B_CPU0_SB_DQS_DP<4>")
	)
	(segment
		(start 290.830254 -236.416596)
		(end 290.355782 -236.416596)
		(width 0.20066)
		(layer "F.Cu")
		(net "M_B_CPU0_SB_DQS_DP<4>")
	)
	(segment
		(start 292.208458 -236.25556)
		(end 291.848286 -236.25556)
		(width 0.20066)
		(layer "F.Cu")
		(net "M_B_CPU0_SB_DQS_DP<4>")
	)
	(segment
		(start 337.96478 -242.295172)
		(end 337.965034 -242.294918)
		(width 0.20066)
		(layer "F.Cu")
		(net "M_B_CPU0_SB_DQS_DP<4>")
	)
	(segment
		(start 295.000172 -235.991654)
		(end 292.922198 -235.991654)
		(width 0.1016)
		(layer "F.Cu")
		(net "M_B_CPU0_SB_DQS_DP<4>")
	)
	(segment
		(start 297.899582 -236.416596)
		(end 297.40987 -236.416596)
		(width 0.20066)
		(layer "F.Cu")
		(net "M_B_CPU0_SB_DQS_DP<4>")
	)
	(segment
		(start 295.141904 -235.991908)
		(end 295.000426 -235.991908)
		(width 0.20066)
		(layer "F.Cu")
		(net "M_B_CPU0_SB_DQS_DP<4>")
	)
	(segment
		(start 292.67531 -235.986066)
		(end 292.477952 -235.986066)
		(width 0.20066)
		(layer "F.Cu")
		(net "M_B_CPU0_SB_DQS_DP<4>")
	)
	(segment
		(start 292.680898 -235.991654)
		(end 292.67531 -235.986066)
		(width 0.101854)
		(layer "F.Cu")
		(net "M_B_CPU0_SB_DQS_DP<4>")
	)
	(segment
		(start 291.848286 -236.25556)
		(end 291.425884 -236.677962)
		(width 0.20066)
		(layer "F.Cu")
		(net "M_B_CPU0_SB_DQS_DP<4>")
	)
	(segment
		(start 295.000426 -235.991908)
		(end 295.000172 -235.991654)
		(width 0.1016)
		(layer "F.Cu")
		(net "M_B_CPU0_SB_DQS_DP<4>")
	)
	(segment
		(start 295.907968 -236.25302)
		(end 295.403016 -236.25302)
		(width 0.20066)
		(layer "F.Cu")
		(net "M_B_CPU0_SB_DQS_DP<4>")
	)
	(segment
		(start 295.403016 -236.25302)
		(end 295.141904 -235.991908)
		(width 0.20066)
		(layer "F.Cu")
		(net "M_B_CPU0_SB_DQS_DP<4>")
	)
	(segment
		(start 292.922198 -235.991654)
		(end 292.680898 -235.991654)
		(width 0.101854)
		(layer "F.Cu")
		(net "M_B_CPU0_SB_DQS_DP<4>")
	)
	(segment
		(start 299.004482 -236.416596)
		(end 297.899582 -236.416596)
		(width 0.20066)
		(layer "F.Cu")
		(net "M_B_CPU0_SB_DQS_DP<4>")
	)
	(segment
		(start 291.09162 -236.677962)
		(end 290.830254 -236.416596)
		(width 0.20066)
		(layer "F.Cu")
		(net "M_B_CPU0_SB_DQS_DP<4>")
	)
	(segment
		(start 296.543984 -236.677962)
		(end 295.907968 -236.25302)
		(width 0.20066)
		(layer "F.Cu")
		(net "M_B_CPU0_SB_DQS_DP<4>")
	)
	(segment
		(start 291.425884 -236.677962)
		(end 291.09162 -236.677962)
		(width 0.20066)
		(layer "F.Cu")
		(net "M_B_CPU0_SB_DQS_DP<4>")
	)
	(segment
		(start 297.148504 -236.677962)
		(end 296.543984 -236.677962)
		(width 0.20066)
		(layer "F.Cu")
		(net "M_B_CPU0_SB_DQS_DP<4>")
	)
	(segment
		(start 292.477952 -235.986066)
		(end 292.208458 -236.25556)
		(width 0.20066)
		(layer "F.Cu")
		(net "M_B_CPU0_SB_DQS_DP<4>")
	)
	(segment
		(start 337.96478 -242.830858)
		(end 337.96478 -242.295172)
		(width 0.20066)
		(layer "F.Cu")
		(net "M_B_CPU0_SB_DQS_DP<4>")
	)
	(segment
		(start 317.032386 -238.358172)
		(end 316.525656 -238.148368)
		(width 0.18288)
		(layer "In2.Cu")
		(net "M_B_CPU0_SB_DQS_DP<4>")
	)
	(segment
		(start 334.392778 -242.619276)
		(end 334.3783 -242.627658)
		(width 0.088646)
		(layer "In2.Cu")
		(net "M_B_CPU0_SB_DQS_DP<4>")
	)
	(segment
		(start 337.965034 -242.294918)
		(end 338.277962 -242.294918)
		(width 0.088646)
		(layer "In2.Cu")
		(net "M_B_CPU0_SB_DQS_DP<4>")
	)
	(segment
		(start 306.16906 -237.6551)
		(end 306.095146 -237.729014)
		(width 0.18288)
		(layer "In2.Cu")
		(net "M_B_CPU0_SB_DQS_DP<4>")
	)
	(segment
		(start 302.156114 -236.524546)
		(end 301.868078 -236.23651)
		(width 0.18288)
		(layer "In2.Cu")
		(net "M_B_CPU0_SB_DQS_DP<4>")
	)
	(segment
		(start 315.951108 -237.775496)
		(end 315.788548 -237.842806)
		(width 0.18288)
		(layer "In2.Cu")
		(net "M_B_CPU0_SB_DQS_DP<4>")
	)
	(segment
		(start 306.413154 -237.411006)
		(end 306.413154 -237.427262)
		(width 0.16002)
		(layer "In2.Cu")
		(net "M_B_CPU0_SB_DQS_DP<4>")
	)
	(segment
		(start 304.47361 -237.427262)
		(end 304.47361 -237.411006)
		(width 0.16002)
		(layer "In2.Cu")
		(net "M_B_CPU0_SB_DQS_DP<4>")
	)
	(segment
		(start 312.291984 -237.68558)
		(end 312.26379 -237.657386)
		(width 0.16002)
		(layer "In2.Cu")
		(net "M_B_CPU0_SB_DQS_DP<4>")
	)
	(segment
		(start 299.793406 -236.86643)
		(end 299.59808 -236.671104)
		(width 0.18288)
		(layer "In2.Cu")
		(net "M_B_CPU0_SB_DQS_DP<4>")
	)
	(segment
		(start 308.252622 -238.59617)
		(end 308.191916 -238.535464)
		(width 0.18288)
		(layer "In2.Cu")
		(net "M_B_CPU0_SB_DQS_DP<4>")
	)
	(segment
		(start 313.71286 -237.6551)
		(end 313.621674 -237.746286)
		(width 0.18288)
		(layer "In2.Cu")
		(net "M_B_CPU0_SB_DQS_DP<4>")
	)
	(segment
		(start 302.184308 -236.55274)
		(end 302.156114 -236.524546)
		(width 0.16002)
		(layer "In2.Cu")
		(net "M_B_CPU0_SB_DQS_DP<4>")
	)
	(segment
		(start 317.194946 -238.290862)
		(end 317.032386 -238.358172)
		(width 0.18288)
		(layer "In2.Cu")
		(net "M_B_CPU0_SB_DQS_DP<4>")
	)
	(segment
		(start 306.095146 -237.729014)
		(end 304.791618 -237.729014)
		(width 0.18288)
		(layer "In2.Cu")
		(net "M_B_CPU0_SB_DQS_DP<4>")
	)
	(segment
		(start 301.868078 -236.23651)
		(end 300.81855 -236.23651)
		(width 0.18288)
		(layer "In2.Cu")
		(net "M_B_CPU0_SB_DQS_DP<4>")
	)
	(segment
		(start 304.673254 -237.626906)
		(end 304.47361 -237.427262)
		(width 0.16002)
		(layer "In2.Cu")
		(net "M_B_CPU0_SB_DQS_DP<4>")
	)
	(segment
		(start 313.75731 -237.626906)
		(end 313.741054 -237.626906)
		(width 0.16002)
		(layer "In2.Cu")
		(net "M_B_CPU0_SB_DQS_DP<4>")
	)
	(segment
		(start 304.68951 -237.626906)
		(end 304.673254 -237.626906)
		(width 0.16002)
		(layer "In2.Cu")
		(net "M_B_CPU0_SB_DQS_DP<4>")
	)
	(segment
		(start 319.605152 -239.423702)
		(end 319.013332 -239.178592)
		(width 0.18288)
		(layer "In2.Cu")
		(net "M_B_CPU0_SB_DQS_DP<4>")
	)
	(segment
		(start 302.541178 -236.90961)
		(end 302.428402 -236.796834)
		(width 0.18288)
		(layer "In2.Cu")
		(net "M_B_CPU0_SB_DQS_DP<4>")
	)
	(segment
		(start 319.013332 -239.178592)
		(end 318.946022 -239.015778)
		(width 0.18288)
		(layer "In2.Cu")
		(net "M_B_CPU0_SB_DQS_DP<4>")
	)
	(segment
		(start 332.508098 -242.622324)
		(end 332.49489 -242.62969)
		(width 0.088646)
		(layer "In2.Cu")
		(net "M_B_CPU0_SB_DQS_DP<4>")
	)
	(segment
		(start 303.972214 -236.90961)
		(end 302.541178 -236.90961)
		(width 0.18288)
		(layer "In2.Cu")
		(net "M_B_CPU0_SB_DQS_DP<4>")
	)
	(segment
		(start 312.04789 -237.457742)
		(end 312.04789 -237.441486)
		(width 0.16002)
		(layer "In2.Cu")
		(net "M_B_CPU0_SB_DQS_DP<4>")
	)
	(segment
		(start 300.50486 -236.5502)
		(end 300.50486 -236.565948)
		(width 0.16002)
		(layer "In2.Cu")
		(net "M_B_CPU0_SB_DQS_DP<4>")
	)
	(segment
		(start 333.452724 -242.619276)
		(end 333.444342 -242.624102)
		(width 0.088646)
		(layer "In2.Cu")
		(net "M_B_CPU0_SB_DQS_DP<4>")
	)
	(segment
		(start 312.247534 -237.657386)
		(end 312.04789 -237.457742)
		(width 0.16002)
		(layer "In2.Cu")
		(net "M_B_CPU0_SB_DQS_DP<4>")
	)
	(segment
		(start 309.856886 -238.277146)
		(end 309.657242 -238.47679)
		(width 0.16002)
		(layer "In2.Cu")
		(net "M_B_CPU0_SB_DQS_DP<4>")
	)
	(segment
		(start 309.612792 -238.504984)
		(end 309.521606 -238.59617)
		(width 0.18288)
		(layer "In2.Cu")
		(net "M_B_CPU0_SB_DQS_DP<4>")
	)
	(segment
		(start 332.513178 -242.619276)
		(end 332.508098 -242.622324)
		(width 0.088646)
		(layer "In2.Cu")
		(net "M_B_CPU0_SB_DQS_DP<4>")
	)
	(segment
		(start 304.791618 -237.729014)
		(end 304.717704 -237.6551)
		(width 0.18288)
		(layer "In2.Cu")
		(net "M_B_CPU0_SB_DQS_DP<4>")
	)
	(segment
		(start 337.227164 -242.61064)
		(end 337.212432 -242.619276)
		(width 0.088646)
		(layer "In2.Cu")
		(net "M_B_CPU0_SB_DQS_DP<4>")
	)
	(segment
		(start 316.525656 -238.148368)
		(end 316.458346 -237.985554)
		(width 0.18288)
		(layer "In2.Cu")
		(net "M_B_CPU0_SB_DQS_DP<4>")
	)
	(segment
		(start 334.40751 -242.61064)
		(end 334.392778 -242.619276)
		(width 0.088646)
		(layer "In2.Cu")
		(net "M_B_CPU0_SB_DQS_DP<4>")
	)
	(segment
		(start 331.493114 -242.543076)
		(end 331.4446 -242.59159)
		(width 0.088646)
		(layer "In2.Cu")
		(net "M_B_CPU0_SB_DQS_DP<4>")
	)
	(segment
		(start 307.675026 -238.018574)
		(end 307.675026 -237.716822)
		(width 0.18288)
		(layer "In2.Cu")
		(net "M_B_CPU0_SB_DQS_DP<4>")
	)
	(segment
		(start 306.623974 -237.200186)
		(end 306.441348 -237.382812)
		(width 0.18288)
		(layer "In2.Cu")
		(net "M_B_CPU0_SB_DQS_DP<4>")
	)
	(segment
		(start 317.769494 -238.66348)
		(end 317.702184 -238.500666)
		(width 0.18288)
		(layer "In2.Cu")
		(net "M_B_CPU0_SB_DQS_DP<4>")
	)
	(segment
		(start 338.277962 -242.294918)
		(end 338.335112 -242.352068)
		(width 0.088646)
		(layer "In2.Cu")
		(net "M_B_CPU0_SB_DQS_DP<4>")
	)
	(segment
		(start 304.445416 -237.382812)
		(end 303.972214 -236.90961)
		(width 0.18288)
		(layer "In2.Cu")
		(net "M_B_CPU0_SB_DQS_DP<4>")
	)
	(segment
		(start 314.214002 -237.15345)
		(end 313.985148 -237.382812)
		(width 0.18288)
		(layer "In2.Cu")
		(net "M_B_CPU0_SB_DQS_DP<4>")
	)
	(segment
		(start 315.35878 -237.665006)
		(end 314.593224 -237.15345)
		(width 0.18288)
		(layer "In2.Cu")
		(net "M_B_CPU0_SB_DQS_DP<4>")
	)
	(segment
		(start 312.04789 -237.441486)
		(end 312.019696 -237.413292)
		(width 0.16002)
		(layer "In2.Cu")
		(net "M_B_CPU0_SB_DQS_DP<4>")
	)
	(segment
		(start 300.81855 -236.23651)
		(end 300.533054 -236.522006)
		(width 0.18288)
		(layer "In2.Cu")
		(net "M_B_CPU0_SB_DQS_DP<4>")
	)
	(segment
		(start 312.26379 -237.657386)
		(end 312.247534 -237.657386)
		(width 0.16002)
		(layer "In2.Cu")
		(net "M_B_CPU0_SB_DQS_DP<4>")
	)
	(segment
		(start 308.147466 -238.50727)
		(end 307.947822 -238.307626)
		(width 0.16002)
		(layer "In2.Cu")
		(net "M_B_CPU0_SB_DQS_DP<4>")
	)
	(segment
		(start 333.078582 -242.619276)
		(end 333.06385 -242.61064)
		(width 0.088646)
		(layer "In2.Cu")
		(net "M_B_CPU0_SB_DQS_DP<4>")
	)
	(segment
		(start 304.717704 -237.6551)
		(end 304.68951 -237.626906)
		(width 0.16002)
		(layer "In2.Cu")
		(net "M_B_CPU0_SB_DQS_DP<4>")
	)
	(segment
		(start 299.25899 -236.671104)
		(end 299.004482 -236.416596)
		(width 0.18288)
		(layer "In2.Cu")
		(net "M_B_CPU0_SB_DQS_DP<4>")
	)
	(segment
		(start 318.438784 -238.805974)
		(end 318.276224 -238.873284)
		(width 0.18288)
		(layer "In2.Cu")
		(net "M_B_CPU0_SB_DQS_DP<4>")
	)
	(segment
		(start 309.521606 -238.59617)
		(end 308.252622 -238.59617)
		(width 0.18288)
		(layer "In2.Cu")
		(net "M_B_CPU0_SB_DQS_DP<4>")
	)
	(segment
		(start 331.004164 -242.531646)
		(end 322.713096 -242.531646)
		(width 0.18288)
		(layer "In2.Cu")
		(net "M_B_CPU0_SB_DQS_DP<4>")
	)
	(segment
		(start 318.946022 -239.015778)
		(end 318.438784 -238.805974)
		(width 0.18288)
		(layer "In2.Cu")
		(net "M_B_CPU0_SB_DQS_DP<4>")
	)
	(segment
		(start 313.985148 -237.382812)
		(end 313.956954 -237.411006)
		(width 0.16002)
		(layer "In2.Cu")
		(net "M_B_CPU0_SB_DQS_DP<4>")
	)
	(segment
		(start 338.161122 -242.614196)
		(end 338.152232 -242.619276)
		(width 0.088646)
		(layer "In2.Cu")
		(net "M_B_CPU0_SB_DQS_DP<4>")
	)
	(segment
		(start 306.413154 -237.427262)
		(end 306.21351 -237.626906)
		(width 0.16002)
		(layer "In2.Cu")
		(net "M_B_CPU0_SB_DQS_DP<4>")
	)
	(segment
		(start 304.47361 -237.411006)
		(end 304.445416 -237.382812)
		(width 0.16002)
		(layer "In2.Cu")
		(net "M_B_CPU0_SB_DQS_DP<4>")
	)
	(segment
		(start 336.287364 -242.61064)
		(end 336.272632 -242.619276)
		(width 0.088646)
		(layer "In2.Cu")
		(net "M_B_CPU0_SB_DQS_DP<4>")
	)
	(segment
		(start 308.191916 -238.535464)
		(end 308.163722 -238.50727)
		(width 0.16002)
		(layer "In2.Cu")
		(net "M_B_CPU0_SB_DQS_DP<4>")
	)
	(segment
		(start 322.713096 -242.531646)
		(end 319.605152 -239.423702)
		(width 0.18288)
		(layer "In2.Cu")
		(net "M_B_CPU0_SB_DQS_DP<4>")
	)
	(segment
		(start 316.458346 -237.985554)
		(end 315.951108 -237.775496)
		(width 0.18288)
		(layer "In2.Cu")
		(net "M_B_CPU0_SB_DQS_DP<4>")
	)
	(segment
		(start 318.276224 -238.873284)
		(end 317.769494 -238.66348)
		(width 0.18288)
		(layer "In2.Cu")
		(net "M_B_CPU0_SB_DQS_DP<4>")
	)
	(segment
		(start 306.197254 -237.626906)
		(end 306.16906 -237.6551)
		(width 0.16002)
		(layer "In2.Cu")
		(net "M_B_CPU0_SB_DQS_DP<4>")
	)
	(segment
		(start 302.184308 -236.568488)
		(end 302.184308 -236.55274)
		(width 0.16002)
		(layer "In2.Cu")
		(net "M_B_CPU0_SB_DQS_DP<4>")
	)
	(segment
		(start 331.4446 -242.59159)
		(end 331.064108 -242.59159)
		(width 0.088646)
		(layer "In2.Cu")
		(net "M_B_CPU0_SB_DQS_DP<4>")
	)
	(segment
		(start 310.923686 -237.19409)
		(end 309.88508 -238.232696)
		(width 0.18288)
		(layer "In2.Cu")
		(net "M_B_CPU0_SB_DQS_DP<4>")
	)
	(segment
		(start 300.260766 -236.794294)
		(end 300.18863 -236.86643)
		(width 0.18288)
		(layer "In2.Cu")
		(net "M_B_CPU0_SB_DQS_DP<4>")
	)
	(segment
		(start 307.919628 -238.263176)
		(end 307.675026 -238.018574)
		(width 0.18288)
		(layer "In2.Cu")
		(net "M_B_CPU0_SB_DQS_DP<4>")
	)
	(segment
		(start 302.428402 -236.796834)
		(end 302.400208 -236.76864)
		(width 0.16002)
		(layer "In2.Cu")
		(net "M_B_CPU0_SB_DQS_DP<4>")
	)
	(segment
		(start 306.21351 -237.626906)
		(end 306.197254 -237.626906)
		(width 0.16002)
		(layer "In2.Cu")
		(net "M_B_CPU0_SB_DQS_DP<4>")
	)
	(segment
		(start 300.18863 -236.86643)
		(end 299.793406 -236.86643)
		(width 0.18288)
		(layer "In2.Cu")
		(net "M_B_CPU0_SB_DQS_DP<4>")
	)
	(segment
		(start 302.400208 -236.76864)
		(end 302.38446 -236.76864)
		(width 0.16002)
		(layer "In2.Cu")
		(net "M_B_CPU0_SB_DQS_DP<4>")
	)
	(segment
		(start 300.28896 -236.7661)
		(end 300.260766 -236.794294)
		(width 0.16002)
		(layer "In2.Cu")
		(net "M_B_CPU0_SB_DQS_DP<4>")
	)
	(segment
		(start 312.019696 -237.413292)
		(end 311.800494 -237.19409)
		(width 0.18288)
		(layer "In2.Cu")
		(net "M_B_CPU0_SB_DQS_DP<4>")
	)
	(segment
		(start 306.441348 -237.382812)
		(end 306.413154 -237.411006)
		(width 0.16002)
		(layer "In2.Cu")
		(net "M_B_CPU0_SB_DQS_DP<4>")
	)
	(segment
		(start 309.856886 -238.26089)
		(end 309.856886 -238.277146)
		(width 0.16002)
		(layer "In2.Cu")
		(net "M_B_CPU0_SB_DQS_DP<4>")
	)
	(segment
		(start 300.304708 -236.7661)
		(end 300.28896 -236.7661)
		(width 0.16002)
		(layer "In2.Cu")
		(net "M_B_CPU0_SB_DQS_DP<4>")
	)
	(segment
		(start 309.657242 -238.47679)
		(end 309.640986 -238.47679)
		(width 0.16002)
		(layer "In2.Cu")
		(net "M_B_CPU0_SB_DQS_DP<4>")
	)
	(segment
		(start 313.621674 -237.746286)
		(end 312.35269 -237.746286)
		(width 0.18288)
		(layer "In2.Cu")
		(net "M_B_CPU0_SB_DQS_DP<4>")
	)
	(segment
		(start 309.88508 -238.232696)
		(end 309.856886 -238.26089)
		(width 0.16002)
		(layer "In2.Cu")
		(net "M_B_CPU0_SB_DQS_DP<4>")
	)
	(segment
		(start 313.956954 -237.427262)
		(end 313.75731 -237.626906)
		(width 0.16002)
		(layer "In2.Cu")
		(net "M_B_CPU0_SB_DQS_DP<4>")
	)
	(segment
		(start 312.35269 -237.746286)
		(end 312.291984 -237.68558)
		(width 0.18288)
		(layer "In2.Cu")
		(net "M_B_CPU0_SB_DQS_DP<4>")
	)
	(segment
		(start 315.788548 -237.842806)
		(end 315.35878 -237.665006)
		(width 0.18288)
		(layer "In2.Cu")
		(net "M_B_CPU0_SB_DQS_DP<4>")
	)
	(segment
		(start 307.947822 -238.307626)
		(end 307.947822 -238.29137)
		(width 0.16002)
		(layer "In2.Cu")
		(net "M_B_CPU0_SB_DQS_DP<4>")
	)
	(segment
		(start 307.675026 -237.716822)
		(end 307.15839 -237.200186)
		(width 0.18288)
		(layer "In2.Cu")
		(net "M_B_CPU0_SB_DQS_DP<4>")
	)
	(segment
		(start 317.702184 -238.500666)
		(end 317.194946 -238.290862)
		(width 0.18288)
		(layer "In2.Cu")
		(net "M_B_CPU0_SB_DQS_DP<4>")
	)
	(segment
		(start 311.800494 -237.19409)
		(end 310.923686 -237.19409)
		(width 0.18288)
		(layer "In2.Cu")
		(net "M_B_CPU0_SB_DQS_DP<4>")
	)
	(segment
		(start 307.947822 -238.29137)
		(end 307.919628 -238.263176)
		(width 0.16002)
		(layer "In2.Cu")
		(net "M_B_CPU0_SB_DQS_DP<4>")
	)
	(segment
		(start 333.473552 -242.607084)
		(end 333.452724 -242.619276)
		(width 0.088646)
		(layer "In2.Cu")
		(net "M_B_CPU0_SB_DQS_DP<4>")
	)
	(segment
		(start 300.50486 -236.565948)
		(end 300.304708 -236.7661)
		(width 0.16002)
		(layer "In2.Cu")
		(net "M_B_CPU0_SB_DQS_DP<4>")
	)
	(segment
		(start 299.59808 -236.671104)
		(end 299.25899 -236.671104)
		(width 0.18288)
		(layer "In2.Cu")
		(net "M_B_CPU0_SB_DQS_DP<4>")
	)
	(segment
		(start 308.163722 -238.50727)
		(end 308.147466 -238.50727)
		(width 0.16002)
		(layer "In2.Cu")
		(net "M_B_CPU0_SB_DQS_DP<4>")
	)
	(segment
		(start 331.064108 -242.59159)
		(end 331.004164 -242.531646)
		(width 0.088646)
		(layer "In2.Cu")
		(net "M_B_CPU0_SB_DQS_DP<4>")
	)
	(segment
		(start 309.640986 -238.47679)
		(end 309.612792 -238.504984)
		(width 0.16002)
		(layer "In2.Cu")
		(net "M_B_CPU0_SB_DQS_DP<4>")
	)
	(segment
		(start 331.854302 -242.543076)
		(end 331.493114 -242.543076)
		(width 0.088646)
		(layer "In2.Cu")
		(net "M_B_CPU0_SB_DQS_DP<4>")
	)
	(segment
		(start 302.38446 -236.76864)
		(end 302.184308 -236.568488)
		(width 0.16002)
		(layer "In2.Cu")
		(net "M_B_CPU0_SB_DQS_DP<4>")
	)
	(segment
		(start 313.956954 -237.411006)
		(end 313.956954 -237.427262)
		(width 0.16002)
		(layer "In2.Cu")
		(net "M_B_CPU0_SB_DQS_DP<4>")
	)
	(segment
		(start 300.533054 -236.522006)
		(end 300.50486 -236.5502)
		(width 0.16002)
		(layer "In2.Cu")
		(net "M_B_CPU0_SB_DQS_DP<4>")
	)
	(segment
		(start 336.272632 -242.619276)
		(end 336.26425 -242.624102)
		(width 0.088646)
		(layer "In2.Cu")
		(net "M_B_CPU0_SB_DQS_DP<4>")
	)
	(segment
		(start 307.15839 -237.200186)
		(end 306.623974 -237.200186)
		(width 0.18288)
		(layer "In2.Cu")
		(net "M_B_CPU0_SB_DQS_DP<4>")
	)
	(segment
		(start 314.593224 -237.15345)
		(end 314.214002 -237.15345)
		(width 0.18288)
		(layer "In2.Cu")
		(net "M_B_CPU0_SB_DQS_DP<4>")
	)
	(segment
		(start 313.741054 -237.626906)
		(end 313.71286 -237.6551)
		(width 0.16002)
		(layer "In2.Cu")
		(net "M_B_CPU0_SB_DQS_DP<4>")
	)
	(arc
		(start 333.444342 -242.624102)
		(mid 333.260834 -242.66938)
		(end 333.078582 -242.619276)
		(width 0.088646)
		(layer "In2.Cu")
		(net "M_B_CPU0_SB_DQS_DP<4>")
	)
	(arc
		(start 332.49489 -242.62969)
		(mid 332.315153 -242.669854)
		(end 332.13802 -242.61953)
		(width 0.088646)
		(layer "In2.Cu")
		(net "M_B_CPU0_SB_DQS_DP<4>")
	)
	(arc
		(start 335.332578 -242.619276)
		(mid 335.14538 -242.669419)
		(end 334.958182 -242.619276)
		(width 0.088646)
		(layer "In2.Cu")
		(net "M_B_CPU0_SB_DQS_DP<4>")
	)
	(arc
		(start 334.958182 -242.619276)
		(mid 334.683953 -242.543351)
		(end 334.40751 -242.61064)
		(width 0.088646)
		(layer "In2.Cu")
		(net "M_B_CPU0_SB_DQS_DP<4>")
	)
	(arc
		(start 338.335112 -242.352068)
		(mid 338.276993 -242.502309)
		(end 338.161122 -242.614196)
		(width 0.088646)
		(layer "In2.Cu")
		(net "M_B_CPU0_SB_DQS_DP<4>")
	)
	(arc
		(start 334.018128 -242.619276)
		(mid 333.747395 -242.543296)
		(end 333.473552 -242.607084)
		(width 0.088646)
		(layer "In2.Cu")
		(net "M_B_CPU0_SB_DQS_DP<4>")
	)
	(arc
		(start 336.838036 -242.619276)
		(mid 336.563807 -242.543351)
		(end 336.287364 -242.61064)
		(width 0.088646)
		(layer "In2.Cu")
		(net "M_B_CPU0_SB_DQS_DP<4>")
	)
	(arc
		(start 333.06385 -242.61064)
		(mid 332.787409 -242.543474)
		(end 332.513178 -242.619276)
		(width 0.088646)
		(layer "In2.Cu")
		(net "M_B_CPU0_SB_DQS_DP<4>")
	)
	(arc
		(start 336.26425 -242.624102)
		(mid 336.080742 -242.66938)
		(end 335.89849 -242.619276)
		(width 0.088646)
		(layer "In2.Cu")
		(net "M_B_CPU0_SB_DQS_DP<4>")
	)
	(arc
		(start 335.89849 -242.619276)
		(mid 335.615534 -242.543407)
		(end 335.332578 -242.619276)
		(width 0.088646)
		(layer "In2.Cu")
		(net "M_B_CPU0_SB_DQS_DP<4>")
	)
	(arc
		(start 334.3783 -242.627658)
		(mid 334.197137 -242.669598)
		(end 334.018128 -242.619276)
		(width 0.088646)
		(layer "In2.Cu")
		(net "M_B_CPU0_SB_DQS_DP<4>")
	)
	(arc
		(start 338.152232 -242.619276)
		(mid 337.965034 -242.669419)
		(end 337.777836 -242.619276)
		(width 0.088646)
		(layer "In2.Cu")
		(net "M_B_CPU0_SB_DQS_DP<4>")
	)
	(arc
		(start 337.212432 -242.619276)
		(mid 337.025234 -242.669419)
		(end 336.838036 -242.619276)
		(width 0.088646)
		(layer "In2.Cu")
		(net "M_B_CPU0_SB_DQS_DP<4>")
	)
	(arc
		(start 337.777836 -242.619276)
		(mid 337.503607 -242.543351)
		(end 337.227164 -242.61064)
		(width 0.088646)
		(layer "In2.Cu")
		(net "M_B_CPU0_SB_DQS_DP<4>")
	)
	(arc
		(start 331.886814 -242.543838)
		(mid 331.870563 -242.543225)
		(end 331.854302 -242.543076)
		(width 0.088646)
		(layer "In2.Cu")
		(net "M_B_CPU0_SB_DQS_DP<4>")
	)
	(arc
		(start 332.13802 -242.61953)
		(mid 332.016867 -242.56691)
		(end 331.886814 -242.543838)
		(width 0.088646)
		(layer "In2.Cu")
		(net "M_B_CPU0_SB_DQS_DP<4>")
	)
	(segment
		(start 293.799514 -200.716642)
		(end 293.250874 -200.716642)
		(width 0.20066)
		(layer "F.Cu")
		(net "M_B_CPU0_SB_DQS_DP<3>")
	)
	(segment
		(start 292.989762 -200.45553)
		(end 292.72103 -200.45553)
		(width 0.20066)
		(layer "F.Cu")
		(net "M_B_CPU0_SB_DQS_DP<3>")
	)
	(segment
		(start 291.556694 -201.141838)
		(end 291.233352 -201.141838)
		(width 0.101854)
		(layer "F.Cu")
		(net "M_B_CPU0_SB_DQS_DP<3>")
	)
	(segment
		(start 292.72103 -200.45553)
		(end 292.295834 -200.880726)
		(width 0.20066)
		(layer "F.Cu")
		(net "M_B_CPU0_SB_DQS_DP<3>")
	)
	(segment
		(start 289.477958 -201.141838)
		(end 289.240976 -201.141838)
		(width 0.101854)
		(layer "F.Cu")
		(net "M_B_CPU0_SB_DQS_DP<3>")
	)
	(segment
		(start 287.47974 -200.45553)
		(end 287.054798 -200.45553)
		(width 0.20066)
		(layer "F.Cu")
		(net "M_B_CPU0_SB_DQS_DP<3>")
	)
	(segment
		(start 333.735934 -225.739198)
		(end 333.735934 -225.203258)
		(width 0.20066)
		(layer "F.Cu")
		(net "M_B_CPU0_SB_DQS_DP<3>")
	)
	(segment
		(start 286.793686 -200.716642)
		(end 286.255714 -200.716642)
		(width 0.20066)
		(layer "F.Cu")
		(net "M_B_CPU0_SB_DQS_DP<3>")
	)
	(segment
		(start 293.250874 -200.716642)
		(end 292.989762 -200.45553)
		(width 0.20066)
		(layer "F.Cu")
		(net "M_B_CPU0_SB_DQS_DP<3>")
	)
	(segment
		(start 291.969952 -200.880726)
		(end 291.70884 -201.141838)
		(width 0.20066)
		(layer "F.Cu")
		(net "M_B_CPU0_SB_DQS_DP<3>")
	)
	(segment
		(start 291.70884 -201.141838)
		(end 291.556694 -201.141838)
		(width 0.20066)
		(layer "F.Cu")
		(net "M_B_CPU0_SB_DQS_DP<3>")
	)
	(segment
		(start 288.742882 -200.880726)
		(end 288.115756 -200.880726)
		(width 0.20066)
		(layer "F.Cu")
		(net "M_B_CPU0_SB_DQS_DP<3>")
	)
	(segment
		(start 287.054798 -200.45553)
		(end 286.793686 -200.716642)
		(width 0.20066)
		(layer "F.Cu")
		(net "M_B_CPU0_SB_DQS_DP<3>")
	)
	(segment
		(start 288.115756 -200.880726)
		(end 287.47974 -200.45553)
		(width 0.20066)
		(layer "F.Cu")
		(net "M_B_CPU0_SB_DQS_DP<3>")
	)
	(segment
		(start 294.904414 -200.716642)
		(end 293.799514 -200.716642)
		(width 0.20066)
		(layer "F.Cu")
		(net "M_B_CPU0_SB_DQS_DP<3>")
	)
	(segment
		(start 292.295834 -200.880726)
		(end 291.969952 -200.880726)
		(width 0.20066)
		(layer "F.Cu")
		(net "M_B_CPU0_SB_DQS_DP<3>")
	)
	(segment
		(start 289.013392 -201.151236)
		(end 288.742882 -200.880726)
		(width 0.20066)
		(layer "F.Cu")
		(net "M_B_CPU0_SB_DQS_DP<3>")
	)
	(segment
		(start 289.240976 -201.141838)
		(end 289.231578 -201.151236)
		(width 0.101854)
		(layer "F.Cu")
		(net "M_B_CPU0_SB_DQS_DP<3>")
	)
	(segment
		(start 289.231578 -201.151236)
		(end 289.013392 -201.151236)
		(width 0.20066)
		(layer "F.Cu")
		(net "M_B_CPU0_SB_DQS_DP<3>")
	)
	(segment
		(start 291.233352 -201.141838)
		(end 289.477958 -201.141838)
		(width 0.1016)
		(layer "F.Cu")
		(net "M_B_CPU0_SB_DQS_DP<3>")
	)
	(segment
		(start 303.392078 -200.729596)
		(end 302.664114 -200.874376)
		(width 0.18288)
		(layer "In4.Cu")
		(net "M_B_CPU0_SB_DQS_DP<3>")
	)
	(segment
		(start 295.185846 -200.43521)
		(end 294.904414 -200.716642)
		(width 0.18288)
		(layer "In4.Cu")
		(net "M_B_CPU0_SB_DQS_DP<3>")
	)
	(segment
		(start 330.731876 -223.326706)
		(end 330.671932 -223.38665)
		(width 0.088646)
		(layer "In4.Cu")
		(net "M_B_CPU0_SB_DQS_DP<3>")
	)
	(segment
		(start 299.463714 -200.874376)
		(end 299.196252 -201.141838)
		(width 0.18288)
		(layer "In4.Cu")
		(net "M_B_CPU0_SB_DQS_DP<3>")
	)
	(segment
		(start 330.671932 -223.38665)
		(end 330.648564 -223.38665)
		(width 0.088646)
		(layer "In4.Cu")
		(net "M_B_CPU0_SB_DQS_DP<3>")
	)
	(segment
		(start 331.107542 -223.326706)
		(end 330.731876 -223.326706)
		(width 0.088646)
		(layer "In4.Cu")
		(net "M_B_CPU0_SB_DQS_DP<3>")
	)
	(segment
		(start 331.330554 -223.549718)
		(end 331.107542 -223.326706)
		(width 0.088646)
		(layer "In4.Cu")
		(net "M_B_CPU0_SB_DQS_DP<3>")
	)
	(segment
		(start 298.53128 -200.866502)
		(end 298.0436 -200.866502)
		(width 0.18288)
		(layer "In4.Cu")
		(net "M_B_CPU0_SB_DQS_DP<3>")
	)
	(segment
		(start 304.04562 -200.076054)
		(end 303.392078 -200.729596)
		(width 0.18288)
		(layer "In4.Cu")
		(net "M_B_CPU0_SB_DQS_DP<3>")
	)
	(segment
		(start 311.977278 -200.076054)
		(end 304.04562 -200.076054)
		(width 0.18288)
		(layer "In4.Cu")
		(net "M_B_CPU0_SB_DQS_DP<3>")
	)
	(segment
		(start 332.421484 -225.12655)
		(end 332.274418 -225.041714)
		(width 0.088646)
		(layer "In4.Cu")
		(net "M_B_CPU0_SB_DQS_DP<3>")
	)
	(segment
		(start 332.274418 -225.041714)
		(end 331.330554 -224.09785)
		(width 0.088646)
		(layer "In4.Cu")
		(net "M_B_CPU0_SB_DQS_DP<3>")
	)
	(segment
		(start 298.0436 -200.866502)
		(end 297.421046 -200.243948)
		(width 0.18288)
		(layer "In4.Cu")
		(net "M_B_CPU0_SB_DQS_DP<3>")
	)
	(segment
		(start 333.735934 -225.203258)
		(end 333.013304 -225.510344)
		(width 0.088646)
		(layer "In4.Cu")
		(net "M_B_CPU0_SB_DQS_DP<3>")
	)
	(segment
		(start 299.196252 -201.141838)
		(end 298.806616 -201.141838)
		(width 0.18288)
		(layer "In4.Cu")
		(net "M_B_CPU0_SB_DQS_DP<3>")
	)
	(segment
		(start 297.421046 -200.243948)
		(end 296.140378 -200.243948)
		(width 0.18288)
		(layer "In4.Cu")
		(net "M_B_CPU0_SB_DQS_DP<3>")
	)
	(segment
		(start 296.140378 -200.243948)
		(end 295.678352 -200.43521)
		(width 0.18288)
		(layer "In4.Cu")
		(net "M_B_CPU0_SB_DQS_DP<3>")
	)
	(segment
		(start 302.664114 -200.874376)
		(end 299.463714 -200.874376)
		(width 0.18288)
		(layer "In4.Cu")
		(net "M_B_CPU0_SB_DQS_DP<3>")
	)
	(segment
		(start 332.985364 -225.5266)
		(end 332.983332 -225.527616)
		(width 0.088646)
		(layer "In4.Cu")
		(net "M_B_CPU0_SB_DQS_DP<3>")
	)
	(segment
		(start 298.806616 -201.141838)
		(end 298.53128 -200.866502)
		(width 0.18288)
		(layer "In4.Cu")
		(net "M_B_CPU0_SB_DQS_DP<3>")
	)
	(segment
		(start 333.013304 -225.510344)
		(end 332.985364 -225.5266)
		(width 0.088646)
		(layer "In4.Cu")
		(net "M_B_CPU0_SB_DQS_DP<3>")
	)
	(segment
		(start 318.165734 -205.298548)
		(end 314.4393 -201.572114)
		(width 0.18288)
		(layer "In4.Cu")
		(net "M_B_CPU0_SB_DQS_DP<3>")
	)
	(segment
		(start 332.421484 -225.203258)
		(end 332.421484 -225.12655)
		(width 0.088646)
		(layer "In4.Cu")
		(net "M_B_CPU0_SB_DQS_DP<3>")
	)
	(segment
		(start 331.330554 -224.09785)
		(end 331.330554 -223.549718)
		(width 0.088646)
		(layer "In4.Cu")
		(net "M_B_CPU0_SB_DQS_DP<3>")
	)
	(segment
		(start 323.729096 -218.728544)
		(end 318.165734 -205.298548)
		(width 0.18288)
		(layer "In4.Cu")
		(net "M_B_CPU0_SB_DQS_DP<3>")
	)
	(segment
		(start 328.387202 -223.38665)
		(end 323.729096 -218.728544)
		(width 0.18288)
		(layer "In4.Cu")
		(net "M_B_CPU0_SB_DQS_DP<3>")
	)
	(segment
		(start 313.473338 -201.572114)
		(end 311.977278 -200.076054)
		(width 0.18288)
		(layer "In4.Cu")
		(net "M_B_CPU0_SB_DQS_DP<3>")
	)
	(segment
		(start 314.4393 -201.572114)
		(end 313.473338 -201.572114)
		(width 0.18288)
		(layer "In4.Cu")
		(net "M_B_CPU0_SB_DQS_DP<3>")
	)
	(segment
		(start 295.678352 -200.43521)
		(end 295.185846 -200.43521)
		(width 0.18288)
		(layer "In4.Cu")
		(net "M_B_CPU0_SB_DQS_DP<3>")
	)
	(segment
		(start 330.648564 -223.38665)
		(end 328.387202 -223.38665)
		(width 0.18288)
		(layer "In4.Cu")
		(net "M_B_CPU0_SB_DQS_DP<3>")
	)
	(arc
		(start 332.983332 -225.527616)
		(mid 332.608857 -225.52757)
		(end 332.421484 -225.203258)
		(width 0.088646)
		(layer "In4.Cu")
		(net "M_B_CPU0_SB_DQS_DP<3>")
	)
	(segment
		(start 287.054798 -209.805524)
		(end 286.793686 -210.066636)
		(width 0.20066)
		(layer "F.Cu")
		(net "M_B_CPU0_SB_DQS_DP<2>")
	)
	(segment
		(start 289.240976 -210.491832)
		(end 289.231578 -210.50123)
		(width 0.101854)
		(layer "F.Cu")
		(net "M_B_CPU0_SB_DQS_DP<2>")
	)
	(segment
		(start 289.013392 -210.50123)
		(end 288.742882 -210.23072)
		(width 0.20066)
		(layer "F.Cu")
		(net "M_B_CPU0_SB_DQS_DP<2>")
	)
	(segment
		(start 292.989762 -209.805524)
		(end 292.72103 -209.805524)
		(width 0.20066)
		(layer "F.Cu")
		(net "M_B_CPU0_SB_DQS_DP<2>")
	)
	(segment
		(start 291.233352 -210.491832)
		(end 289.477958 -210.491832)
		(width 0.1016)
		(layer "F.Cu")
		(net "M_B_CPU0_SB_DQS_DP<2>")
	)
	(segment
		(start 293.250874 -210.066636)
		(end 292.989762 -209.805524)
		(width 0.20066)
		(layer "F.Cu")
		(net "M_B_CPU0_SB_DQS_DP<2>")
	)
	(segment
		(start 293.799514 -210.066636)
		(end 293.250874 -210.066636)
		(width 0.20066)
		(layer "F.Cu")
		(net "M_B_CPU0_SB_DQS_DP<2>")
	)
	(segment
		(start 294.904414 -210.066636)
		(end 293.799514 -210.066636)
		(width 0.20066)
		(layer "F.Cu")
		(net "M_B_CPU0_SB_DQS_DP<2>")
	)
	(segment
		(start 286.793686 -210.066636)
		(end 286.255714 -210.066636)
		(width 0.20066)
		(layer "F.Cu")
		(net "M_B_CPU0_SB_DQS_DP<2>")
	)
	(segment
		(start 289.231578 -210.50123)
		(end 289.013392 -210.50123)
		(width 0.20066)
		(layer "F.Cu")
		(net "M_B_CPU0_SB_DQS_DP<2>")
	)
	(segment
		(start 291.556694 -210.491832)
		(end 291.233352 -210.491832)
		(width 0.101854)
		(layer "F.Cu")
		(net "M_B_CPU0_SB_DQS_DP<2>")
	)
	(segment
		(start 288.742882 -210.23072)
		(end 288.115756 -210.23072)
		(width 0.20066)
		(layer "F.Cu")
		(net "M_B_CPU0_SB_DQS_DP<2>")
	)
	(segment
		(start 291.70884 -210.491832)
		(end 291.556694 -210.491832)
		(width 0.20066)
		(layer "F.Cu")
		(net "M_B_CPU0_SB_DQS_DP<2>")
	)
	(segment
		(start 337.02498 -228.1809)
		(end 337.025234 -228.180646)
		(width 0.20066)
		(layer "F.Cu")
		(net "M_B_CPU0_SB_DQS_DP<2>")
	)
	(segment
		(start 292.295834 -210.23072)
		(end 291.969952 -210.23072)
		(width 0.20066)
		(layer "F.Cu")
		(net "M_B_CPU0_SB_DQS_DP<2>")
	)
	(segment
		(start 337.025234 -228.180646)
		(end 337.025234 -227.64496)
		(width 0.20066)
		(layer "F.Cu")
		(net "M_B_CPU0_SB_DQS_DP<2>")
	)
	(segment
		(start 292.72103 -209.805524)
		(end 292.295834 -210.23072)
		(width 0.20066)
		(layer "F.Cu")
		(net "M_B_CPU0_SB_DQS_DP<2>")
	)
	(segment
		(start 288.115756 -210.23072)
		(end 287.47974 -209.805524)
		(width 0.20066)
		(layer "F.Cu")
		(net "M_B_CPU0_SB_DQS_DP<2>")
	)
	(segment
		(start 287.47974 -209.805524)
		(end 287.054798 -209.805524)
		(width 0.20066)
		(layer "F.Cu")
		(net "M_B_CPU0_SB_DQS_DP<2>")
	)
	(segment
		(start 291.969952 -210.23072)
		(end 291.70884 -210.491832)
		(width 0.20066)
		(layer "F.Cu")
		(net "M_B_CPU0_SB_DQS_DP<2>")
	)
	(segment
		(start 289.477958 -210.491832)
		(end 289.240976 -210.491832)
		(width 0.101854)
		(layer "F.Cu")
		(net "M_B_CPU0_SB_DQS_DP<2>")
	)
	(segment
		(start 336.274664 -227.968302)
		(end 336.272632 -227.969318)
		(width 0.088646)
		(layer "In2.Cu")
		(net "M_B_CPU0_SB_DQS_DP<2>")
	)
	(segment
		(start 314.176156 -209.580226)
		(end 314.160408 -209.580226)
		(width 0.16002)
		(layer "In2.Cu")
		(net "M_B_CPU0_SB_DQS_DP<2>")
	)
	(segment
		(start 309.856886 -209.056224)
		(end 309.657242 -208.85658)
		(width 0.16002)
		(layer "In2.Cu")
		(net "M_B_CPU0_SB_DQS_DP<2>")
	)
	(segment
		(start 302.316388 -210.64601)
		(end 302.288194 -210.674204)
		(width 0.16002)
		(layer "In2.Cu")
		(net "M_B_CPU0_SB_DQS_DP<2>")
	)
	(segment
		(start 309.657242 -208.85658)
		(end 309.640986 -208.85658)
		(width 0.16002)
		(layer "In2.Cu")
		(net "M_B_CPU0_SB_DQS_DP<2>")
	)
	(segment
		(start 333.170784 -223.59112)
		(end 333.170784 -223.575626)
		(width 0.088646)
		(layer "In2.Cu")
		(net "M_B_CPU0_SB_DQS_DP<2>")
	)
	(segment
		(start 317.877444 -209.605118)
		(end 314.746132 -209.605118)
		(width 0.18288)
		(layer "In2.Cu")
		(net "M_B_CPU0_SB_DQS_DP<2>")
	)
	(segment
		(start 311.798208 -209.580226)
		(end 311.770014 -209.552032)
		(width 0.16002)
		(layer "In2.Cu")
		(net "M_B_CPU0_SB_DQS_DP<2>")
	)
	(segment
		(start 308.116986 -208.85658)
		(end 307.917342 -209.056224)
		(width 0.16002)
		(layer "In2.Cu")
		(net "M_B_CPU0_SB_DQS_DP<2>")
	)
	(segment
		(start 311.770014 -209.552032)
		(end 311.61863 -209.400648)
		(width 0.18288)
		(layer "In2.Cu")
		(net "M_B_CPU0_SB_DQS_DP<2>")
	)
	(segment
		(start 331.943964 -223.387158)
		(end 331.659484 -223.387158)
		(width 0.18288)
		(layer "In2.Cu")
		(net "M_B_CPU0_SB_DQS_DP<2>")
	)
	(segment
		(start 304.681636 -210.007454)
		(end 304.498502 -209.82432)
		(width 0.18288)
		(layer "In2.Cu")
		(net "M_B_CPU0_SB_DQS_DP<2>")
	)
	(segment
		(start 335.898236 -227.969318)
		(end 335.889346 -227.964238)
		(width 0.088646)
		(layer "In2.Cu")
		(net "M_B_CPU0_SB_DQS_DP<2>")
	)
	(segment
		(start 312.225436 -210.007454)
		(end 312.042302 -209.82432)
		(width 0.18288)
		(layer "In2.Cu")
		(net "M_B_CPU0_SB_DQS_DP<2>")
	)
	(segment
		(start 306.416456 -209.780378)
		(end 306.416456 -209.796126)
		(width 0.16002)
		(layer "In2.Cu")
		(net "M_B_CPU0_SB_DQS_DP<2>")
	)
	(segment
		(start 335.710784 -227.64496)
		(end 335.710784 -227.538788)
		(width 0.088646)
		(layer "In2.Cu")
		(net "M_B_CPU0_SB_DQS_DP<2>")
	)
	(segment
		(start 333.453994 -224.065592)
		(end 333.452978 -224.065084)
		(width 0.088646)
		(layer "In2.Cu")
		(net "M_B_CPU0_SB_DQS_DP<2>")
	)
	(segment
		(start 296.850816 -209.719926)
		(end 296.835068 -209.719926)
		(width 0.16002)
		(layer "In2.Cu")
		(net "M_B_CPU0_SB_DQS_DP<2>")
	)
	(segment
		(start 313.960256 -209.780378)
		(end 313.960256 -209.796126)
		(width 0.16002)
		(layer "In2.Cu")
		(net "M_B_CPU0_SB_DQS_DP<2>")
	)
	(segment
		(start 300.15434 -210.43011)
		(end 300.126146 -210.401916)
		(width 0.16002)
		(layer "In2.Cu")
		(net "M_B_CPU0_SB_DQS_DP<2>")
	)
	(segment
		(start 297.079162 -209.96402)
		(end 297.050968 -209.935826)
		(width 0.16002)
		(layer "In2.Cu")
		(net "M_B_CPU0_SB_DQS_DP<2>")
	)
	(segment
		(start 298.555664 -210.234276)
		(end 297.349418 -210.234276)
		(width 0.18288)
		(layer "In2.Cu")
		(net "M_B_CPU0_SB_DQS_DP<2>")
	)
	(segment
		(start 304.498502 -209.82432)
		(end 304.470308 -209.796126)
		(width 0.16002)
		(layer "In2.Cu")
		(net "M_B_CPU0_SB_DQS_DP<2>")
	)
	(segment
		(start 304.270156 -209.580226)
		(end 304.254408 -209.580226)
		(width 0.16002)
		(layer "In2.Cu")
		(net "M_B_CPU0_SB_DQS_DP<2>")
	)
	(segment
		(start 300.37024 -210.64601)
		(end 300.37024 -210.630262)
		(width 0.16002)
		(layer "In2.Cu")
		(net "M_B_CPU0_SB_DQS_DP<2>")
	)
	(segment
		(start 299.943012 -210.218782)
		(end 299.460158 -210.218782)
		(width 0.18288)
		(layer "In2.Cu")
		(net "M_B_CPU0_SB_DQS_DP<2>")
	)
	(segment
		(start 314.160408 -209.580226)
		(end 313.960256 -209.780378)
		(width 0.16002)
		(layer "In2.Cu")
		(net "M_B_CPU0_SB_DQS_DP<2>")
	)
	(segment
		(start 296.835068 -209.719926)
		(end 296.806874 -209.691732)
		(width 0.16002)
		(layer "In2.Cu")
		(net "M_B_CPU0_SB_DQS_DP<2>")
	)
	(segment
		(start 308.253892 -208.73593)
		(end 308.161436 -208.828386)
		(width 0.18288)
		(layer "In2.Cu")
		(net "M_B_CPU0_SB_DQS_DP<2>")
	)
	(segment
		(start 300.170088 -210.43011)
		(end 300.15434 -210.43011)
		(width 0.16002)
		(layer "In2.Cu")
		(net "M_B_CPU0_SB_DQS_DP<2>")
	)
	(segment
		(start 334.86725 -226.509072)
		(end 334.86725 -226.509326)
		(width 0.088646)
		(layer "In2.Cu")
		(net "M_B_CPU0_SB_DQS_DP<2>")
	)
	(segment
		(start 314.746132 -209.605118)
		(end 314.587128 -209.446114)
		(width 0.18288)
		(layer "In2.Cu")
		(net "M_B_CPU0_SB_DQS_DP<2>")
	)
	(segment
		(start 310.185054 -209.400648)
		(end 309.88508 -209.100674)
		(width 0.18288)
		(layer "In2.Cu")
		(net "M_B_CPU0_SB_DQS_DP<2>")
	)
	(segment
		(start 302.288194 -210.674204)
		(end 302.10506 -210.857338)
		(width 0.18288)
		(layer "In2.Cu")
		(net "M_B_CPU0_SB_DQS_DP<2>")
	)
	(segment
		(start 299.187362 -210.491578)
		(end 298.812966 -210.491578)
		(width 0.18288)
		(layer "In2.Cu")
		(net "M_B_CPU0_SB_DQS_DP<2>")
	)
	(segment
		(start 312.014108 -209.780378)
		(end 311.813956 -209.580226)
		(width 0.16002)
		(layer "In2.Cu")
		(net "M_B_CPU0_SB_DQS_DP<2>")
	)
	(segment
		(start 314.310268 -209.446114)
		(end 314.20435 -209.552032)
		(width 0.18288)
		(layer "In2.Cu")
		(net "M_B_CPU0_SB_DQS_DP<2>")
	)
	(segment
		(start 312.014108 -209.796126)
		(end 312.014108 -209.780378)
		(width 0.16002)
		(layer "In2.Cu")
		(net "M_B_CPU0_SB_DQS_DP<2>")
	)
	(segment
		(start 306.877212 -209.33537)
		(end 306.66055 -209.552032)
		(width 0.18288)
		(layer "In2.Cu")
		(net "M_B_CPU0_SB_DQS_DP<2>")
	)
	(segment
		(start 297.050968 -209.920078)
		(end 296.850816 -209.719926)
		(width 0.16002)
		(layer "In2.Cu")
		(net "M_B_CPU0_SB_DQS_DP<2>")
	)
	(segment
		(start 304.040032 -209.36585)
		(end 303.596548 -209.36585)
		(width 0.18288)
		(layer "In2.Cu")
		(net "M_B_CPU0_SB_DQS_DP<2>")
	)
	(segment
		(start 297.050968 -209.935826)
		(end 297.050968 -209.920078)
		(width 0.16002)
		(layer "In2.Cu")
		(net "M_B_CPU0_SB_DQS_DP<2>")
	)
	(segment
		(start 307.889148 -209.100674)
		(end 307.654452 -209.33537)
		(width 0.18288)
		(layer "In2.Cu")
		(net "M_B_CPU0_SB_DQS_DP<2>")
	)
	(segment
		(start 300.398434 -210.674204)
		(end 300.37024 -210.64601)
		(width 0.16002)
		(layer "In2.Cu")
		(net "M_B_CPU0_SB_DQS_DP<2>")
	)
	(segment
		(start 311.813956 -209.580226)
		(end 311.798208 -209.580226)
		(width 0.16002)
		(layer "In2.Cu")
		(net "M_B_CPU0_SB_DQS_DP<2>")
	)
	(segment
		(start 295.585896 -209.796634)
		(end 295.174416 -209.796634)
		(width 0.18288)
		(layer "In2.Cu")
		(net "M_B_CPU0_SB_DQS_DP<2>")
	)
	(segment
		(start 309.640986 -208.85658)
		(end 309.612792 -208.828386)
		(width 0.16002)
		(layer "In2.Cu")
		(net "M_B_CPU0_SB_DQS_DP<2>")
	)
	(segment
		(start 307.654452 -209.33537)
		(end 306.877212 -209.33537)
		(width 0.18288)
		(layer "In2.Cu")
		(net "M_B_CPU0_SB_DQS_DP<2>")
	)
	(segment
		(start 334.872076 -226.511866)
		(end 334.867758 -226.509326)
		(width 0.088646)
		(layer "In2.Cu")
		(net "M_B_CPU0_SB_DQS_DP<2>")
	)
	(segment
		(start 299.460158 -210.218782)
		(end 299.187362 -210.491578)
		(width 0.18288)
		(layer "In2.Cu")
		(net "M_B_CPU0_SB_DQS_DP<2>")
	)
	(segment
		(start 296.203116 -209.54111)
		(end 295.585896 -209.796634)
		(width 0.18288)
		(layer "In2.Cu")
		(net "M_B_CPU0_SB_DQS_DP<2>")
	)
	(segment
		(start 302.51654 -210.43011)
		(end 302.316388 -210.630262)
		(width 0.16002)
		(layer "In2.Cu")
		(net "M_B_CPU0_SB_DQS_DP<2>")
	)
	(segment
		(start 333.461868 -224.070164)
		(end 333.453994 -224.065592)
		(width 0.088646)
		(layer "In2.Cu")
		(net "M_B_CPU0_SB_DQS_DP<2>")
	)
	(segment
		(start 308.161436 -208.828386)
		(end 308.133242 -208.85658)
		(width 0.16002)
		(layer "In2.Cu")
		(net "M_B_CPU0_SB_DQS_DP<2>")
	)
	(segment
		(start 296.656252 -209.54111)
		(end 296.203116 -209.54111)
		(width 0.18288)
		(layer "In2.Cu")
		(net "M_B_CPU0_SB_DQS_DP<2>")
	)
	(segment
		(start 337.025234 -227.64496)
		(end 336.302604 -227.952046)
		(width 0.088646)
		(layer "In2.Cu")
		(net "M_B_CPU0_SB_DQS_DP<2>")
	)
	(segment
		(start 304.226214 -209.552032)
		(end 304.040032 -209.36585)
		(width 0.18288)
		(layer "In2.Cu")
		(net "M_B_CPU0_SB_DQS_DP<2>")
	)
	(segment
		(start 306.205128 -210.007454)
		(end 304.681636 -210.007454)
		(width 0.18288)
		(layer "In2.Cu")
		(net "M_B_CPU0_SB_DQS_DP<2>")
	)
	(segment
		(start 300.37024 -210.630262)
		(end 300.170088 -210.43011)
		(width 0.16002)
		(layer "In2.Cu")
		(net "M_B_CPU0_SB_DQS_DP<2>")
	)
	(segment
		(start 313.748928 -210.007454)
		(end 312.225436 -210.007454)
		(width 0.18288)
		(layer "In2.Cu")
		(net "M_B_CPU0_SB_DQS_DP<2>")
	)
	(segment
		(start 302.316388 -210.630262)
		(end 302.316388 -210.64601)
		(width 0.16002)
		(layer "In2.Cu")
		(net "M_B_CPU0_SB_DQS_DP<2>")
	)
	(segment
		(start 306.388262 -209.82432)
		(end 306.205128 -210.007454)
		(width 0.18288)
		(layer "In2.Cu")
		(net "M_B_CPU0_SB_DQS_DP<2>")
	)
	(segment
		(start 296.806874 -209.691732)
		(end 296.656252 -209.54111)
		(width 0.18288)
		(layer "In2.Cu")
		(net "M_B_CPU0_SB_DQS_DP<2>")
	)
	(segment
		(start 309.88508 -209.100674)
		(end 309.856886 -209.07248)
		(width 0.16002)
		(layer "In2.Cu")
		(net "M_B_CPU0_SB_DQS_DP<2>")
	)
	(segment
		(start 331.659484 -223.387158)
		(end 317.877444 -209.605118)
		(width 0.18288)
		(layer "In2.Cu")
		(net "M_B_CPU0_SB_DQS_DP<2>")
	)
	(segment
		(start 295.174416 -209.796634)
		(end 294.904414 -210.066636)
		(width 0.18288)
		(layer "In2.Cu")
		(net "M_B_CPU0_SB_DQS_DP<2>")
	)
	(segment
		(start 306.616608 -209.580226)
		(end 306.416456 -209.780378)
		(width 0.16002)
		(layer "In2.Cu")
		(net "M_B_CPU0_SB_DQS_DP<2>")
	)
	(segment
		(start 334.58023 -226.027234)
		(end 334.58023 -226.008692)
		(width 0.088646)
		(layer "In2.Cu")
		(net "M_B_CPU0_SB_DQS_DP<2>")
	)
	(segment
		(start 303.596548 -209.36585)
		(end 302.560482 -210.401916)
		(width 0.18288)
		(layer "In2.Cu")
		(net "M_B_CPU0_SB_DQS_DP<2>")
	)
	(segment
		(start 313.932062 -209.82432)
		(end 313.748928 -210.007454)
		(width 0.18288)
		(layer "In2.Cu")
		(net "M_B_CPU0_SB_DQS_DP<2>")
	)
	(segment
		(start 306.66055 -209.552032)
		(end 306.632356 -209.580226)
		(width 0.16002)
		(layer "In2.Cu")
		(net "M_B_CPU0_SB_DQS_DP<2>")
	)
	(segment
		(start 336.302604 -227.952046)
		(end 336.274664 -227.968302)
		(width 0.088646)
		(layer "In2.Cu")
		(net "M_B_CPU0_SB_DQS_DP<2>")
	)
	(segment
		(start 302.560482 -210.401916)
		(end 302.532288 -210.43011)
		(width 0.16002)
		(layer "In2.Cu")
		(net "M_B_CPU0_SB_DQS_DP<2>")
	)
	(segment
		(start 304.470308 -209.780378)
		(end 304.270156 -209.580226)
		(width 0.16002)
		(layer "In2.Cu")
		(net "M_B_CPU0_SB_DQS_DP<2>")
	)
	(segment
		(start 333.932022 -224.88398)
		(end 333.91094 -224.871788)
		(width 0.088646)
		(layer "In2.Cu")
		(net "M_B_CPU0_SB_DQS_DP<2>")
	)
	(segment
		(start 298.812966 -210.491578)
		(end 298.555664 -210.234276)
		(width 0.18288)
		(layer "In2.Cu")
		(net "M_B_CPU0_SB_DQS_DP<2>")
	)
	(segment
		(start 309.520336 -208.73593)
		(end 308.253892 -208.73593)
		(width 0.18288)
		(layer "In2.Cu")
		(net "M_B_CPU0_SB_DQS_DP<2>")
	)
	(segment
		(start 334.86725 -226.509326)
		(end 334.862678 -226.506786)
		(width 0.088646)
		(layer "In2.Cu")
		(net "M_B_CPU0_SB_DQS_DP<2>")
	)
	(segment
		(start 300.581568 -210.857338)
		(end 300.398434 -210.674204)
		(width 0.18288)
		(layer "In2.Cu")
		(net "M_B_CPU0_SB_DQS_DP<2>")
	)
	(segment
		(start 335.710784 -227.538788)
		(end 335.332832 -227.320348)
		(width 0.088646)
		(layer "In2.Cu")
		(net "M_B_CPU0_SB_DQS_DP<2>")
	)
	(segment
		(start 302.532288 -210.43011)
		(end 302.51654 -210.43011)
		(width 0.16002)
		(layer "In2.Cu")
		(net "M_B_CPU0_SB_DQS_DP<2>")
	)
	(segment
		(start 312.042302 -209.82432)
		(end 312.014108 -209.796126)
		(width 0.16002)
		(layer "In2.Cu")
		(net "M_B_CPU0_SB_DQS_DP<2>")
	)
	(segment
		(start 306.632356 -209.580226)
		(end 306.616608 -209.580226)
		(width 0.16002)
		(layer "In2.Cu")
		(net "M_B_CPU0_SB_DQS_DP<2>")
	)
	(segment
		(start 300.126146 -210.401916)
		(end 299.943012 -210.218782)
		(width 0.18288)
		(layer "In2.Cu")
		(net "M_B_CPU0_SB_DQS_DP<2>")
	)
	(segment
		(start 309.612792 -208.828386)
		(end 309.520336 -208.73593)
		(width 0.18288)
		(layer "In2.Cu")
		(net "M_B_CPU0_SB_DQS_DP<2>")
	)
	(segment
		(start 302.10506 -210.857338)
		(end 300.581568 -210.857338)
		(width 0.18288)
		(layer "In2.Cu")
		(net "M_B_CPU0_SB_DQS_DP<2>")
	)
	(segment
		(start 297.349418 -210.234276)
		(end 297.079162 -209.96402)
		(width 0.18288)
		(layer "In2.Cu")
		(net "M_B_CPU0_SB_DQS_DP<2>")
	)
	(segment
		(start 304.470308 -209.796126)
		(end 304.470308 -209.780378)
		(width 0.16002)
		(layer "In2.Cu")
		(net "M_B_CPU0_SB_DQS_DP<2>")
	)
	(segment
		(start 314.587128 -209.446114)
		(end 314.310268 -209.446114)
		(width 0.18288)
		(layer "In2.Cu")
		(net "M_B_CPU0_SB_DQS_DP<2>")
	)
	(segment
		(start 309.856886 -209.07248)
		(end 309.856886 -209.056224)
		(width 0.16002)
		(layer "In2.Cu")
		(net "M_B_CPU0_SB_DQS_DP<2>")
	)
	(segment
		(start 306.416456 -209.796126)
		(end 306.388262 -209.82432)
		(width 0.16002)
		(layer "In2.Cu")
		(net "M_B_CPU0_SB_DQS_DP<2>")
	)
	(segment
		(start 311.61863 -209.400648)
		(end 310.185054 -209.400648)
		(width 0.18288)
		(layer "In2.Cu")
		(net "M_B_CPU0_SB_DQS_DP<2>")
	)
	(segment
		(start 332.003908 -223.327214)
		(end 331.943964 -223.387158)
		(width 0.088646)
		(layer "In2.Cu")
		(net "M_B_CPU0_SB_DQS_DP<2>")
	)
	(segment
		(start 334.110584 -225.2218)
		(end 334.110584 -225.203258)
		(width 0.088646)
		(layer "In2.Cu")
		(net "M_B_CPU0_SB_DQS_DP<2>")
	)
	(segment
		(start 313.960256 -209.796126)
		(end 313.932062 -209.82432)
		(width 0.16002)
		(layer "In2.Cu")
		(net "M_B_CPU0_SB_DQS_DP<2>")
	)
	(segment
		(start 307.917342 -209.056224)
		(end 307.917342 -209.07248)
		(width 0.16002)
		(layer "In2.Cu")
		(net "M_B_CPU0_SB_DQS_DP<2>")
	)
	(segment
		(start 334.867758 -226.509326)
		(end 334.86725 -226.509072)
		(width 0.088646)
		(layer "In2.Cu")
		(net "M_B_CPU0_SB_DQS_DP<2>")
	)
	(segment
		(start 304.254408 -209.580226)
		(end 304.226214 -209.552032)
		(width 0.16002)
		(layer "In2.Cu")
		(net "M_B_CPU0_SB_DQS_DP<2>")
	)
	(segment
		(start 332.32598 -223.327214)
		(end 332.003908 -223.327214)
		(width 0.088646)
		(layer "In2.Cu")
		(net "M_B_CPU0_SB_DQS_DP<2>")
	)
	(segment
		(start 308.133242 -208.85658)
		(end 308.116986 -208.85658)
		(width 0.16002)
		(layer "In2.Cu")
		(net "M_B_CPU0_SB_DQS_DP<2>")
	)
	(segment
		(start 307.917342 -209.07248)
		(end 307.889148 -209.100674)
		(width 0.16002)
		(layer "In2.Cu")
		(net "M_B_CPU0_SB_DQS_DP<2>")
	)
	(segment
		(start 332.992222 -223.256348)
		(end 332.983332 -223.251268)
		(width 0.088646)
		(layer "In2.Cu")
		(net "M_B_CPU0_SB_DQS_DP<2>")
	)
	(segment
		(start 314.20435 -209.552032)
		(end 314.176156 -209.580226)
		(width 0.16002)
		(layer "In2.Cu")
		(net "M_B_CPU0_SB_DQS_DP<2>")
	)
	(arc
		(start 332.983332 -223.251268)
		(mid 332.796134 -223.201125)
		(end 332.608936 -223.251268)
		(width 0.088646)
		(layer "In2.Cu")
		(net "M_B_CPU0_SB_DQS_DP<2>")
	)
	(arc
		(start 334.393032 -225.69297)
		(mid 334.190746 -225.493989)
		(end 334.110584 -225.2218)
		(width 0.088646)
		(layer "In2.Cu")
		(net "M_B_CPU0_SB_DQS_DP<2>")
	)
	(arc
		(start 334.862678 -226.506786)
		(mid 334.658343 -226.304181)
		(end 334.58023 -226.027234)
		(width 0.088646)
		(layer "In2.Cu")
		(net "M_B_CPU0_SB_DQS_DP<2>")
	)
	(arc
		(start 335.889346 -227.964238)
		(mid 335.758432 -227.827878)
		(end 335.710784 -227.64496)
		(width 0.088646)
		(layer "In2.Cu")
		(net "M_B_CPU0_SB_DQS_DP<2>")
	)
	(arc
		(start 332.608936 -223.251268)
		(mid 332.472463 -223.307902)
		(end 332.32598 -223.327214)
		(width 0.088646)
		(layer "In2.Cu")
		(net "M_B_CPU0_SB_DQS_DP<2>")
	)
	(arc
		(start 333.64043 -224.389442)
		(mid 333.592751 -224.206542)
		(end 333.461868 -224.070164)
		(width 0.088646)
		(layer "In2.Cu")
		(net "M_B_CPU0_SB_DQS_DP<2>")
	)
	(arc
		(start 335.050638 -226.831144)
		(mid 335.002959 -226.648244)
		(end 334.872076 -226.511866)
		(width 0.088646)
		(layer "In2.Cu")
		(net "M_B_CPU0_SB_DQS_DP<2>")
	)
	(arc
		(start 334.58023 -226.008692)
		(mid 334.52796 -225.826327)
		(end 334.393032 -225.69297)
		(width 0.088646)
		(layer "In2.Cu")
		(net "M_B_CPU0_SB_DQS_DP<2>")
	)
	(arc
		(start 333.91094 -224.871788)
		(mid 333.712712 -224.66594)
		(end 333.64043 -224.389442)
		(width 0.088646)
		(layer "In2.Cu")
		(net "M_B_CPU0_SB_DQS_DP<2>")
	)
	(arc
		(start 333.452978 -224.065084)
		(mid 333.250155 -223.864853)
		(end 333.170784 -223.59112)
		(width 0.088646)
		(layer "In2.Cu")
		(net "M_B_CPU0_SB_DQS_DP<2>")
	)
	(arc
		(start 335.332832 -227.320348)
		(mid 335.12625 -227.113522)
		(end 335.050638 -226.831144)
		(width 0.088646)
		(layer "In2.Cu")
		(net "M_B_CPU0_SB_DQS_DP<2>")
	)
	(arc
		(start 334.110584 -225.203258)
		(mid 334.062905 -225.020358)
		(end 333.932022 -224.88398)
		(width 0.088646)
		(layer "In2.Cu")
		(net "M_B_CPU0_SB_DQS_DP<2>")
	)
	(arc
		(start 336.272632 -227.969318)
		(mid 336.085434 -228.019461)
		(end 335.898236 -227.969318)
		(width 0.088646)
		(layer "In2.Cu")
		(net "M_B_CPU0_SB_DQS_DP<2>")
	)
	(arc
		(start 333.170784 -223.575626)
		(mid 333.123105 -223.392726)
		(end 332.992222 -223.256348)
		(width 0.088646)
		(layer "In2.Cu")
		(net "M_B_CPU0_SB_DQS_DP<2>")
	)
	(segment
		(start 294.904414 -219.41663)
		(end 293.799514 -219.41663)
		(width 0.20066)
		(layer "F.Cu")
		(net "M_B_CPU0_SB_DQS_DP<1>")
	)
	(segment
		(start 289.013392 -219.851224)
		(end 288.742882 -219.580714)
		(width 0.20066)
		(layer "F.Cu")
		(net "M_B_CPU0_SB_DQS_DP<1>")
	)
	(segment
		(start 293.250874 -219.41663)
		(end 292.989762 -219.155518)
		(width 0.20066)
		(layer "F.Cu")
		(net "M_B_CPU0_SB_DQS_DP<1>")
	)
	(segment
		(start 287.054798 -219.155518)
		(end 286.793686 -219.41663)
		(width 0.20066)
		(layer "F.Cu")
		(net "M_B_CPU0_SB_DQS_DP<1>")
	)
	(segment
		(start 292.989762 -219.155518)
		(end 292.72103 -219.155518)
		(width 0.20066)
		(layer "F.Cu")
		(net "M_B_CPU0_SB_DQS_DP<1>")
	)
	(segment
		(start 291.70884 -219.841826)
		(end 291.556948 -219.841826)
		(width 0.20066)
		(layer "F.Cu")
		(net "M_B_CPU0_SB_DQS_DP<1>")
	)
	(segment
		(start 292.295834 -219.580714)
		(end 291.969952 -219.580714)
		(width 0.20066)
		(layer "F.Cu")
		(net "M_B_CPU0_SB_DQS_DP<1>")
	)
	(segment
		(start 287.47974 -219.155518)
		(end 287.054798 -219.155518)
		(width 0.20066)
		(layer "F.Cu")
		(net "M_B_CPU0_SB_DQS_DP<1>")
	)
	(segment
		(start 293.799514 -219.41663)
		(end 293.250874 -219.41663)
		(width 0.20066)
		(layer "F.Cu")
		(net "M_B_CPU0_SB_DQS_DP<1>")
	)
	(segment
		(start 337.02498 -232.528618)
		(end 337.025234 -232.528364)
		(width 0.20066)
		(layer "F.Cu")
		(net "M_B_CPU0_SB_DQS_DP<1>")
	)
	(segment
		(start 291.556948 -219.841826)
		(end 291.233352 -219.841826)
		(width 0.101854)
		(layer "F.Cu")
		(net "M_B_CPU0_SB_DQS_DP<1>")
	)
	(segment
		(start 289.231832 -219.85097)
		(end 289.231578 -219.851224)
		(width 0.20066)
		(layer "F.Cu")
		(net "M_B_CPU0_SB_DQS_DP<1>")
	)
	(segment
		(start 291.233352 -219.841826)
		(end 289.477958 -219.841826)
		(width 0.1016)
		(layer "F.Cu")
		(net "M_B_CPU0_SB_DQS_DP<1>")
	)
	(segment
		(start 289.240976 -219.841826)
		(end 289.231832 -219.85097)
		(width 0.101854)
		(layer "F.Cu")
		(net "M_B_CPU0_SB_DQS_DP<1>")
	)
	(segment
		(start 289.477958 -219.841826)
		(end 289.240976 -219.841826)
		(width 0.101854)
		(layer "F.Cu")
		(net "M_B_CPU0_SB_DQS_DP<1>")
	)
	(segment
		(start 289.231578 -219.851224)
		(end 289.013392 -219.851224)
		(width 0.20066)
		(layer "F.Cu")
		(net "M_B_CPU0_SB_DQS_DP<1>")
	)
	(segment
		(start 337.02498 -233.064304)
		(end 337.02498 -232.528618)
		(width 0.20066)
		(layer "F.Cu")
		(net "M_B_CPU0_SB_DQS_DP<1>")
	)
	(segment
		(start 288.742882 -219.580714)
		(end 288.115502 -219.580714)
		(width 0.20066)
		(layer "F.Cu")
		(net "M_B_CPU0_SB_DQS_DP<1>")
	)
	(segment
		(start 292.72103 -219.155518)
		(end 292.295834 -219.580714)
		(width 0.20066)
		(layer "F.Cu")
		(net "M_B_CPU0_SB_DQS_DP<1>")
	)
	(segment
		(start 291.969952 -219.580714)
		(end 291.70884 -219.841826)
		(width 0.20066)
		(layer "F.Cu")
		(net "M_B_CPU0_SB_DQS_DP<1>")
	)
	(segment
		(start 288.115502 -219.580714)
		(end 287.47974 -219.155518)
		(width 0.20066)
		(layer "F.Cu")
		(net "M_B_CPU0_SB_DQS_DP<1>")
	)
	(segment
		(start 286.793686 -219.41663)
		(end 286.255714 -219.41663)
		(width 0.20066)
		(layer "F.Cu")
		(net "M_B_CPU0_SB_DQS_DP<1>")
	)
	(segment
		(start 314.160408 -218.93022)
		(end 313.960256 -219.130372)
		(width 0.16002)
		(layer "In2.Cu")
		(net "M_B_CPU0_SB_DQS_DP<1>")
	)
	(segment
		(start 296.656252 -218.891104)
		(end 296.203116 -218.891104)
		(width 0.18288)
		(layer "In2.Cu")
		(net "M_B_CPU0_SB_DQS_DP<1>")
	)
	(segment
		(start 313.932062 -219.174314)
		(end 313.76747 -219.338906)
		(width 0.18288)
		(layer "In2.Cu")
		(net "M_B_CPU0_SB_DQS_DP<1>")
	)
	(segment
		(start 306.416456 -220.846142)
		(end 306.388262 -220.874336)
		(width 0.16002)
		(layer "In2.Cu")
		(net "M_B_CPU0_SB_DQS_DP<1>")
	)
	(segment
		(start 331.984096 -233.09326)
		(end 331.556106 -232.66527)
		(width 0.088646)
		(layer "In2.Cu")
		(net "M_B_CPU0_SB_DQS_DP<1>")
	)
	(segment
		(start 330.976732 -232.454958)
		(end 317.359792 -218.838018)
		(width 0.18288)
		(layer "In2.Cu")
		(net "M_B_CPU0_SB_DQS_DP<1>")
	)
	(segment
		(start 306.632356 -220.630242)
		(end 306.616608 -220.630242)
		(width 0.16002)
		(layer "In2.Cu")
		(net "M_B_CPU0_SB_DQS_DP<1>")
	)
	(segment
		(start 311.798208 -218.93022)
		(end 311.770014 -218.902026)
		(width 0.16002)
		(layer "In2.Cu")
		(net "M_B_CPU0_SB_DQS_DP<1>")
	)
	(segment
		(start 300.170088 -219.780104)
		(end 300.15434 -219.780104)
		(width 0.16002)
		(layer "In2.Cu")
		(net "M_B_CPU0_SB_DQS_DP<1>")
	)
	(segment
		(start 297.079162 -219.314014)
		(end 297.050968 -219.28582)
		(width 0.16002)
		(layer "In2.Cu")
		(net "M_B_CPU0_SB_DQS_DP<1>")
	)
	(segment
		(start 332.998064 -233.026458)
		(end 332.983332 -233.017822)
		(width 0.088646)
		(layer "In2.Cu")
		(net "M_B_CPU0_SB_DQS_DP<1>")
	)
	(segment
		(start 297.050968 -219.270072)
		(end 296.850816 -219.06992)
		(width 0.16002)
		(layer "In2.Cu")
		(net "M_B_CPU0_SB_DQS_DP<1>")
	)
	(segment
		(start 302.288194 -220.024198)
		(end 302.123602 -220.18879)
		(width 0.18288)
		(layer "In2.Cu")
		(net "M_B_CPU0_SB_DQS_DP<1>")
	)
	(segment
		(start 306.22367 -221.038928)
		(end 304.663094 -221.038928)
		(width 0.18288)
		(layer "In2.Cu")
		(net "M_B_CPU0_SB_DQS_DP<1>")
	)
	(segment
		(start 309.860188 -219.980256)
		(end 309.860188 -219.996004)
		(width 0.16002)
		(layer "In2.Cu")
		(net "M_B_CPU0_SB_DQS_DP<1>")
	)
	(segment
		(start 302.532288 -219.780104)
		(end 302.51654 -219.780104)
		(width 0.16002)
		(layer "In2.Cu")
		(net "M_B_CPU0_SB_DQS_DP<1>")
	)
	(segment
		(start 304.470308 -220.830394)
		(end 304.270156 -220.630242)
		(width 0.16002)
		(layer "In2.Cu")
		(net "M_B_CPU0_SB_DQS_DP<1>")
	)
	(segment
		(start 309.831994 -220.024198)
		(end 309.664862 -220.19133)
		(width 0.18288)
		(layer "In2.Cu")
		(net "M_B_CPU0_SB_DQS_DP<1>")
	)
	(segment
		(start 313.960256 -219.130372)
		(end 313.960256 -219.14612)
		(width 0.16002)
		(layer "In2.Cu")
		(net "M_B_CPU0_SB_DQS_DP<1>")
	)
	(segment
		(start 302.674782 -219.63761)
		(end 302.560482 -219.75191)
		(width 0.18288)
		(layer "In2.Cu")
		(net "M_B_CPU0_SB_DQS_DP<1>")
	)
	(segment
		(start 306.66055 -220.602048)
		(end 306.632356 -220.630242)
		(width 0.16002)
		(layer "In2.Cu")
		(net "M_B_CPU0_SB_DQS_DP<1>")
	)
	(segment
		(start 304.470308 -220.846142)
		(end 304.470308 -220.830394)
		(width 0.16002)
		(layer "In2.Cu")
		(net "M_B_CPU0_SB_DQS_DP<1>")
	)
	(segment
		(start 310.06034 -219.780104)
		(end 309.860188 -219.980256)
		(width 0.16002)
		(layer "In2.Cu")
		(net "M_B_CPU0_SB_DQS_DP<1>")
	)
	(segment
		(start 304.254408 -220.630242)
		(end 304.226214 -220.602048)
		(width 0.16002)
		(layer "In2.Cu")
		(net "M_B_CPU0_SB_DQS_DP<1>")
	)
	(segment
		(start 304.226214 -220.602048)
		(end 303.261776 -219.63761)
		(width 0.18288)
		(layer "In2.Cu")
		(net "M_B_CPU0_SB_DQS_DP<1>")
	)
	(segment
		(start 302.123602 -220.18879)
		(end 300.563026 -220.18879)
		(width 0.18288)
		(layer "In2.Cu")
		(net "M_B_CPU0_SB_DQS_DP<1>")
	)
	(segment
		(start 302.316388 -219.980256)
		(end 302.316388 -219.996004)
		(width 0.16002)
		(layer "In2.Cu")
		(net "M_B_CPU0_SB_DQS_DP<1>")
	)
	(segment
		(start 308.053486 -220.19133)
		(end 307.761386 -219.89923)
		(width 0.18288)
		(layer "In2.Cu")
		(net "M_B_CPU0_SB_DQS_DP<1>")
	)
	(segment
		(start 306.616608 -220.630242)
		(end 306.416456 -220.830394)
		(width 0.16002)
		(layer "In2.Cu")
		(net "M_B_CPU0_SB_DQS_DP<1>")
	)
	(segment
		(start 300.398434 -220.024198)
		(end 300.37024 -219.996004)
		(width 0.16002)
		(layer "In2.Cu")
		(net "M_B_CPU0_SB_DQS_DP<1>")
	)
	(segment
		(start 295.174416 -219.146628)
		(end 294.904414 -219.41663)
		(width 0.18288)
		(layer "In2.Cu")
		(net "M_B_CPU0_SB_DQS_DP<1>")
	)
	(segment
		(start 335.428082 -233.017568)
		(end 335.428336 -233.017822)
		(width 0.088646)
		(layer "In2.Cu")
		(net "M_B_CPU0_SB_DQS_DP<1>")
	)
	(segment
		(start 300.563026 -220.18879)
		(end 300.398434 -220.024198)
		(width 0.18288)
		(layer "In2.Cu")
		(net "M_B_CPU0_SB_DQS_DP<1>")
	)
	(segment
		(start 298.555664 -219.58427)
		(end 297.349418 -219.58427)
		(width 0.18288)
		(layer "In2.Cu")
		(net "M_B_CPU0_SB_DQS_DP<1>")
	)
	(segment
		(start 310.076088 -219.780104)
		(end 310.06034 -219.780104)
		(width 0.16002)
		(layer "In2.Cu")
		(net "M_B_CPU0_SB_DQS_DP<1>")
	)
	(segment
		(start 312.014108 -219.130372)
		(end 311.813956 -218.93022)
		(width 0.16002)
		(layer "In2.Cu")
		(net "M_B_CPU0_SB_DQS_DP<1>")
	)
	(segment
		(start 311.813956 -218.93022)
		(end 311.798208 -218.93022)
		(width 0.16002)
		(layer "In2.Cu")
		(net "M_B_CPU0_SB_DQS_DP<1>")
	)
	(segment
		(start 306.388262 -220.874336)
		(end 306.22367 -221.038928)
		(width 0.18288)
		(layer "In2.Cu")
		(net "M_B_CPU0_SB_DQS_DP<1>")
	)
	(segment
		(start 312.042302 -219.174314)
		(end 312.014108 -219.14612)
		(width 0.16002)
		(layer "In2.Cu")
		(net "M_B_CPU0_SB_DQS_DP<1>")
	)
	(segment
		(start 300.37024 -219.996004)
		(end 300.37024 -219.980256)
		(width 0.16002)
		(layer "In2.Cu")
		(net "M_B_CPU0_SB_DQS_DP<1>")
	)
	(segment
		(start 331.556106 -232.66527)
		(end 331.27188 -232.66527)
		(width 0.088646)
		(layer "In2.Cu")
		(net "M_B_CPU0_SB_DQS_DP<1>")
	)
	(segment
		(start 337.025234 -232.528364)
		(end 336.348324 -232.80878)
		(width 0.088646)
		(layer "In2.Cu")
		(net "M_B_CPU0_SB_DQS_DP<1>")
	)
	(segment
		(start 300.15434 -219.780104)
		(end 300.126146 -219.75191)
		(width 0.16002)
		(layer "In2.Cu")
		(net "M_B_CPU0_SB_DQS_DP<1>")
	)
	(segment
		(start 302.560482 -219.75191)
		(end 302.532288 -219.780104)
		(width 0.16002)
		(layer "In2.Cu")
		(net "M_B_CPU0_SB_DQS_DP<1>")
	)
	(segment
		(start 296.806874 -219.041726)
		(end 296.656252 -218.891104)
		(width 0.18288)
		(layer "In2.Cu")
		(net "M_B_CPU0_SB_DQS_DP<1>")
	)
	(segment
		(start 310.75249 -219.555314)
		(end 310.300878 -219.555314)
		(width 0.18288)
		(layer "In2.Cu")
		(net "M_B_CPU0_SB_DQS_DP<1>")
	)
	(segment
		(start 300.126146 -219.75191)
		(end 299.943012 -219.568776)
		(width 0.18288)
		(layer "In2.Cu")
		(net "M_B_CPU0_SB_DQS_DP<1>")
	)
	(segment
		(start 311.770014 -218.902026)
		(end 311.714388 -218.8464)
		(width 0.18288)
		(layer "In2.Cu")
		(net "M_B_CPU0_SB_DQS_DP<1>")
	)
	(segment
		(start 309.860188 -219.996004)
		(end 309.831994 -220.024198)
		(width 0.16002)
		(layer "In2.Cu")
		(net "M_B_CPU0_SB_DQS_DP<1>")
	)
	(segment
		(start 297.050968 -219.28582)
		(end 297.050968 -219.270072)
		(width 0.16002)
		(layer "In2.Cu")
		(net "M_B_CPU0_SB_DQS_DP<1>")
	)
	(segment
		(start 336.01279 -232.922826)
		(end 335.592166 -232.922826)
		(width 0.088646)
		(layer "In2.Cu")
		(net "M_B_CPU0_SB_DQS_DP<1>")
	)
	(segment
		(start 303.261776 -219.63761)
		(end 302.674782 -219.63761)
		(width 0.18288)
		(layer "In2.Cu")
		(net "M_B_CPU0_SB_DQS_DP<1>")
	)
	(segment
		(start 307.761386 -219.89923)
		(end 307.363368 -219.89923)
		(width 0.18288)
		(layer "In2.Cu")
		(net "M_B_CPU0_SB_DQS_DP<1>")
	)
	(segment
		(start 309.664862 -220.19133)
		(end 308.053486 -220.19133)
		(width 0.18288)
		(layer "In2.Cu")
		(net "M_B_CPU0_SB_DQS_DP<1>")
	)
	(segment
		(start 310.300878 -219.555314)
		(end 310.104282 -219.75191)
		(width 0.18288)
		(layer "In2.Cu")
		(net "M_B_CPU0_SB_DQS_DP<1>")
	)
	(segment
		(start 314.176156 -218.93022)
		(end 314.160408 -218.93022)
		(width 0.16002)
		(layer "In2.Cu")
		(net "M_B_CPU0_SB_DQS_DP<1>")
	)
	(segment
		(start 304.270156 -220.630242)
		(end 304.254408 -220.630242)
		(width 0.16002)
		(layer "In2.Cu")
		(net "M_B_CPU0_SB_DQS_DP<1>")
	)
	(segment
		(start 310.104282 -219.75191)
		(end 310.076088 -219.780104)
		(width 0.16002)
		(layer "In2.Cu")
		(net "M_B_CPU0_SB_DQS_DP<1>")
	)
	(segment
		(start 312.206894 -219.338906)
		(end 312.042302 -219.174314)
		(width 0.18288)
		(layer "In2.Cu")
		(net "M_B_CPU0_SB_DQS_DP<1>")
	)
	(segment
		(start 314.20435 -218.902026)
		(end 314.176156 -218.93022)
		(width 0.16002)
		(layer "In2.Cu")
		(net "M_B_CPU0_SB_DQS_DP<1>")
	)
	(segment
		(start 317.359792 -218.838018)
		(end 314.268358 -218.838018)
		(width 0.18288)
		(layer "In2.Cu")
		(net "M_B_CPU0_SB_DQS_DP<1>")
	)
	(segment
		(start 302.51654 -219.780104)
		(end 302.316388 -219.980256)
		(width 0.16002)
		(layer "In2.Cu")
		(net "M_B_CPU0_SB_DQS_DP<1>")
	)
	(segment
		(start 332.608936 -233.017822)
		(end 332.608682 -233.017314)
		(width 0.088646)
		(layer "In2.Cu")
		(net "M_B_CPU0_SB_DQS_DP<1>")
	)
	(segment
		(start 336.348324 -232.80878)
		(end 336.272378 -232.852722)
		(width 0.088646)
		(layer "In2.Cu")
		(net "M_B_CPU0_SB_DQS_DP<1>")
	)
	(segment
		(start 313.960256 -219.14612)
		(end 313.932062 -219.174314)
		(width 0.16002)
		(layer "In2.Cu")
		(net "M_B_CPU0_SB_DQS_DP<1>")
	)
	(segment
		(start 299.460158 -219.568776)
		(end 299.187362 -219.841572)
		(width 0.18288)
		(layer "In2.Cu")
		(net "M_B_CPU0_SB_DQS_DP<1>")
	)
	(segment
		(start 295.585896 -219.146628)
		(end 295.174416 -219.146628)
		(width 0.18288)
		(layer "In2.Cu")
		(net "M_B_CPU0_SB_DQS_DP<1>")
	)
	(segment
		(start 304.663094 -221.038928)
		(end 304.498502 -220.874336)
		(width 0.18288)
		(layer "In2.Cu")
		(net "M_B_CPU0_SB_DQS_DP<1>")
	)
	(segment
		(start 298.812966 -219.841572)
		(end 298.555664 -219.58427)
		(width 0.18288)
		(layer "In2.Cu")
		(net "M_B_CPU0_SB_DQS_DP<1>")
	)
	(segment
		(start 312.014108 -219.14612)
		(end 312.014108 -219.130372)
		(width 0.16002)
		(layer "In2.Cu")
		(net "M_B_CPU0_SB_DQS_DP<1>")
	)
	(segment
		(start 331.27188 -232.66527)
		(end 331.061568 -232.454958)
		(width 0.088646)
		(layer "In2.Cu")
		(net "M_B_CPU0_SB_DQS_DP<1>")
	)
	(segment
		(start 297.349418 -219.58427)
		(end 297.079162 -219.314014)
		(width 0.18288)
		(layer "In2.Cu")
		(net "M_B_CPU0_SB_DQS_DP<1>")
	)
	(segment
		(start 335.592166 -232.922826)
		(end 335.428082 -233.017568)
		(width 0.088646)
		(layer "In2.Cu")
		(net "M_B_CPU0_SB_DQS_DP<1>")
	)
	(segment
		(start 302.316388 -219.996004)
		(end 302.288194 -220.024198)
		(width 0.16002)
		(layer "In2.Cu")
		(net "M_B_CPU0_SB_DQS_DP<1>")
	)
	(segment
		(start 331.061568 -232.454958)
		(end 330.976732 -232.454958)
		(width 0.088646)
		(layer "In2.Cu")
		(net "M_B_CPU0_SB_DQS_DP<1>")
	)
	(segment
		(start 332.326234 -233.09326)
		(end 331.984096 -233.09326)
		(width 0.088646)
		(layer "In2.Cu")
		(net "M_B_CPU0_SB_DQS_DP<1>")
	)
	(segment
		(start 332.608682 -233.017314)
		(end 332.608428 -233.017568)
		(width 0.088646)
		(layer "In2.Cu")
		(net "M_B_CPU0_SB_DQS_DP<1>")
	)
	(segment
		(start 296.850816 -219.06992)
		(end 296.835068 -219.06992)
		(width 0.16002)
		(layer "In2.Cu")
		(net "M_B_CPU0_SB_DQS_DP<1>")
	)
	(segment
		(start 304.498502 -220.874336)
		(end 304.470308 -220.846142)
		(width 0.16002)
		(layer "In2.Cu")
		(net "M_B_CPU0_SB_DQS_DP<1>")
	)
	(segment
		(start 306.416456 -220.830394)
		(end 306.416456 -220.846142)
		(width 0.16002)
		(layer "In2.Cu")
		(net "M_B_CPU0_SB_DQS_DP<1>")
	)
	(segment
		(start 296.203116 -218.891104)
		(end 295.585896 -219.146628)
		(width 0.18288)
		(layer "In2.Cu")
		(net "M_B_CPU0_SB_DQS_DP<1>")
	)
	(segment
		(start 314.268358 -218.838018)
		(end 314.20435 -218.902026)
		(width 0.18288)
		(layer "In2.Cu")
		(net "M_B_CPU0_SB_DQS_DP<1>")
	)
	(segment
		(start 313.76747 -219.338906)
		(end 312.206894 -219.338906)
		(width 0.18288)
		(layer "In2.Cu")
		(net "M_B_CPU0_SB_DQS_DP<1>")
	)
	(segment
		(start 296.835068 -219.06992)
		(end 296.806874 -219.041726)
		(width 0.16002)
		(layer "In2.Cu")
		(net "M_B_CPU0_SB_DQS_DP<1>")
	)
	(segment
		(start 300.37024 -219.980256)
		(end 300.170088 -219.780104)
		(width 0.16002)
		(layer "In2.Cu")
		(net "M_B_CPU0_SB_DQS_DP<1>")
	)
	(segment
		(start 311.461404 -218.8464)
		(end 310.75249 -219.555314)
		(width 0.18288)
		(layer "In2.Cu")
		(net "M_B_CPU0_SB_DQS_DP<1>")
	)
	(segment
		(start 299.943012 -219.568776)
		(end 299.460158 -219.568776)
		(width 0.18288)
		(layer "In2.Cu")
		(net "M_B_CPU0_SB_DQS_DP<1>")
	)
	(segment
		(start 299.187362 -219.841572)
		(end 298.812966 -219.841572)
		(width 0.18288)
		(layer "In2.Cu")
		(net "M_B_CPU0_SB_DQS_DP<1>")
	)
	(segment
		(start 307.363368 -219.89923)
		(end 306.66055 -220.602048)
		(width 0.18288)
		(layer "In2.Cu")
		(net "M_B_CPU0_SB_DQS_DP<1>")
	)
	(segment
		(start 311.714388 -218.8464)
		(end 311.461404 -218.8464)
		(width 0.18288)
		(layer "In2.Cu")
		(net "M_B_CPU0_SB_DQS_DP<1>")
	)
	(arc
		(start 332.983332 -233.017822)
		(mid 332.796134 -232.967679)
		(end 332.608936 -233.017822)
		(width 0.088646)
		(layer "In2.Cu")
		(net "M_B_CPU0_SB_DQS_DP<1>")
	)
	(arc
		(start 334.488536 -233.017822)
		(mid 334.205834 -233.093598)
		(end 333.923132 -233.017822)
		(width 0.088646)
		(layer "In2.Cu")
		(net "M_B_CPU0_SB_DQS_DP<1>")
	)
	(arc
		(start 332.608428 -233.017568)
		(mid 332.472309 -233.073969)
		(end 332.326234 -233.09326)
		(width 0.088646)
		(layer "In2.Cu")
		(net "M_B_CPU0_SB_DQS_DP<1>")
	)
	(arc
		(start 335.428336 -233.017822)
		(mid 335.145634 -233.093598)
		(end 334.862932 -233.017822)
		(width 0.088646)
		(layer "In2.Cu")
		(net "M_B_CPU0_SB_DQS_DP<1>")
	)
	(arc
		(start 336.272378 -232.852722)
		(mid 336.147235 -232.904996)
		(end 336.01279 -232.922826)
		(width 0.088646)
		(layer "In2.Cu")
		(net "M_B_CPU0_SB_DQS_DP<1>")
	)
	(arc
		(start 334.862932 -233.017822)
		(mid 334.675734 -232.967679)
		(end 334.488536 -233.017822)
		(width 0.088646)
		(layer "In2.Cu")
		(net "M_B_CPU0_SB_DQS_DP<1>")
	)
	(arc
		(start 333.923132 -233.017822)
		(mid 333.735934 -232.967679)
		(end 333.548736 -233.017822)
		(width 0.088646)
		(layer "In2.Cu")
		(net "M_B_CPU0_SB_DQS_DP<1>")
	)
	(arc
		(start 333.548736 -233.017822)
		(mid 333.274537 -233.093657)
		(end 332.998064 -233.026458)
		(width 0.088646)
		(layer "In2.Cu")
		(net "M_B_CPU0_SB_DQS_DP<1>")
	)
	(segment
		(start 289.240976 -229.19182)
		(end 289.231578 -229.201218)
		(width 0.101854)
		(layer "F.Cu")
		(net "M_B_CPU0_SB_DQS_DP<0>")
	)
	(segment
		(start 294.904414 -228.766624)
		(end 293.799514 -228.766624)
		(width 0.20066)
		(layer "F.Cu")
		(net "M_B_CPU0_SB_DQS_DP<0>")
	)
	(segment
		(start 293.250874 -228.766624)
		(end 292.989762 -228.505512)
		(width 0.20066)
		(layer "F.Cu")
		(net "M_B_CPU0_SB_DQS_DP<0>")
	)
	(segment
		(start 289.231578 -229.201218)
		(end 289.013392 -229.201218)
		(width 0.20066)
		(layer "F.Cu")
		(net "M_B_CPU0_SB_DQS_DP<0>")
	)
	(segment
		(start 292.72103 -228.505512)
		(end 292.295834 -228.930708)
		(width 0.20066)
		(layer "F.Cu")
		(net "M_B_CPU0_SB_DQS_DP<0>")
	)
	(segment
		(start 286.793686 -228.766624)
		(end 286.255714 -228.766624)
		(width 0.20066)
		(layer "F.Cu")
		(net "M_B_CPU0_SB_DQS_DP<0>")
	)
	(segment
		(start 291.969952 -228.930708)
		(end 291.70884 -229.19182)
		(width 0.20066)
		(layer "F.Cu")
		(net "M_B_CPU0_SB_DQS_DP<0>")
	)
	(segment
		(start 292.295834 -228.930708)
		(end 291.969952 -228.930708)
		(width 0.20066)
		(layer "F.Cu")
		(net "M_B_CPU0_SB_DQS_DP<0>")
	)
	(segment
		(start 291.70884 -229.19182)
		(end 291.556694 -229.19182)
		(width 0.20066)
		(layer "F.Cu")
		(net "M_B_CPU0_SB_DQS_DP<0>")
	)
	(segment
		(start 287.47974 -228.505512)
		(end 287.054798 -228.505512)
		(width 0.20066)
		(layer "F.Cu")
		(net "M_B_CPU0_SB_DQS_DP<0>")
	)
	(segment
		(start 293.799514 -228.766624)
		(end 293.250874 -228.766624)
		(width 0.20066)
		(layer "F.Cu")
		(net "M_B_CPU0_SB_DQS_DP<0>")
	)
	(segment
		(start 340.314534 -234.97032)
		(end 340.31428 -234.970066)
		(width 0.20066)
		(layer "F.Cu")
		(net "M_B_CPU0_SB_DQS_DP<0>")
	)
	(segment
		(start 292.989762 -228.505512)
		(end 292.72103 -228.505512)
		(width 0.20066)
		(layer "F.Cu")
		(net "M_B_CPU0_SB_DQS_DP<0>")
	)
	(segment
		(start 289.013392 -229.201218)
		(end 288.742882 -228.930708)
		(width 0.20066)
		(layer "F.Cu")
		(net "M_B_CPU0_SB_DQS_DP<0>")
	)
	(segment
		(start 291.556694 -229.19182)
		(end 291.233352 -229.19182)
		(width 0.101854)
		(layer "F.Cu")
		(net "M_B_CPU0_SB_DQS_DP<0>")
	)
	(segment
		(start 291.233352 -229.19182)
		(end 289.477958 -229.19182)
		(width 0.1016)
		(layer "F.Cu")
		(net "M_B_CPU0_SB_DQS_DP<0>")
	)
	(segment
		(start 288.742882 -228.930708)
		(end 288.115756 -228.930708)
		(width 0.20066)
		(layer "F.Cu")
		(net "M_B_CPU0_SB_DQS_DP<0>")
	)
	(segment
		(start 289.477958 -229.19182)
		(end 289.240976 -229.19182)
		(width 0.101854)
		(layer "F.Cu")
		(net "M_B_CPU0_SB_DQS_DP<0>")
	)
	(segment
		(start 288.115756 -228.930708)
		(end 287.47974 -228.505512)
		(width 0.20066)
		(layer "F.Cu")
		(net "M_B_CPU0_SB_DQS_DP<0>")
	)
	(segment
		(start 340.314534 -235.506006)
		(end 340.314534 -234.97032)
		(width 0.20066)
		(layer "F.Cu")
		(net "M_B_CPU0_SB_DQS_DP<0>")
	)
	(segment
		(start 287.054798 -228.505512)
		(end 286.793686 -228.766624)
		(width 0.20066)
		(layer "F.Cu")
		(net "M_B_CPU0_SB_DQS_DP<0>")
	)
	(segment
		(start 307.262022 -226.569778)
		(end 306.873656 -226.958144)
		(width 0.18288)
		(layer "In4.Cu")
		(net "M_B_CPU0_SB_DQS_DP<0>")
	)
	(segment
		(start 332.099158 -235.480606)
		(end 330.752196 -235.480606)
		(width 0.088646)
		(layer "In4.Cu")
		(net "M_B_CPU0_SB_DQS_DP<0>")
	)
	(segment
		(start 339.282278 -235.339128)
		(end 338.926678 -235.339128)
		(width 0.088646)
		(layer "In4.Cu")
		(net "M_B_CPU0_SB_DQS_DP<0>")
	)
	(segment
		(start 299.597064 -228.651562)
		(end 299.440092 -228.808534)
		(width 0.18288)
		(layer "In4.Cu")
		(net "M_B_CPU0_SB_DQS_DP<0>")
	)
	(segment
		(start 299.178472 -229.19182)
		(end 298.806616 -229.19182)
		(width 0.18288)
		(layer "In4.Cu")
		(net "M_B_CPU0_SB_DQS_DP<0>")
	)
	(segment
		(start 306.30876 -226.958144)
		(end 305.110388 -228.156516)
		(width 0.18288)
		(layer "In4.Cu")
		(net "M_B_CPU0_SB_DQS_DP<0>")
	)
	(segment
		(start 301.13986 -228.651562)
		(end 299.597064 -228.651562)
		(width 0.18288)
		(layer "In4.Cu")
		(net "M_B_CPU0_SB_DQS_DP<0>")
	)
	(segment
		(start 332.170786 -235.408978)
		(end 332.099158 -235.480606)
		(width 0.088646)
		(layer "In4.Cu")
		(net "M_B_CPU0_SB_DQS_DP<0>")
	)
	(segment
		(start 333.467964 -235.46816)
		(end 333.453232 -235.459524)
		(width 0.088646)
		(layer "In4.Cu")
		(net "M_B_CPU0_SB_DQS_DP<0>")
	)
	(segment
		(start 305.110388 -228.156516)
		(end 301.634906 -228.156516)
		(width 0.18288)
		(layer "In4.Cu")
		(net "M_B_CPU0_SB_DQS_DP<0>")
	)
	(segment
		(start 314.263532 -229.19182)
		(end 313.894216 -229.19182)
		(width 0.18288)
		(layer "In4.Cu")
		(net "M_B_CPU0_SB_DQS_DP<0>")
	)
	(segment
		(start 338.926678 -235.339128)
		(end 338.703158 -235.467906)
		(width 0.088646)
		(layer "In4.Cu")
		(net "M_B_CPU0_SB_DQS_DP<0>")
	)
	(segment
		(start 315.388244 -228.899974)
		(end 314.555378 -228.899974)
		(width 0.18288)
		(layer "In4.Cu")
		(net "M_B_CPU0_SB_DQS_DP<0>")
	)
	(segment
		(start 308.97703 -227.21697)
		(end 308.329838 -226.569778)
		(width 0.18288)
		(layer "In4.Cu")
		(net "M_B_CPU0_SB_DQS_DP<0>")
	)
	(segment
		(start 298.077636 -228.955854)
		(end 297.37685 -228.255068)
		(width 0.18288)
		(layer "In4.Cu")
		(net "M_B_CPU0_SB_DQS_DP<0>")
	)
	(segment
		(start 339.97392 -235.059982)
		(end 339.548724 -235.30179)
		(width 0.088646)
		(layer "In4.Cu")
		(net "M_B_CPU0_SB_DQS_DP<0>")
	)
	(segment
		(start 332.32598 -235.408978)
		(end 332.170786 -235.408978)
		(width 0.088646)
		(layer "In4.Cu")
		(net "M_B_CPU0_SB_DQS_DP<0>")
	)
	(segment
		(start 295.740074 -228.255068)
		(end 295.50995 -228.485192)
		(width 0.18288)
		(layer "In4.Cu")
		(net "M_B_CPU0_SB_DQS_DP<0>")
	)
	(segment
		(start 330.648564 -235.54055)
		(end 322.02882 -235.54055)
		(width 0.18288)
		(layer "In4.Cu")
		(net "M_B_CPU0_SB_DQS_DP<0>")
	)
	(segment
		(start 310.470296 -227.211636)
		(end 310.190388 -227.491544)
		(width 0.18288)
		(layer "In4.Cu")
		(net "M_B_CPU0_SB_DQS_DP<0>")
	)
	(segment
		(start 309.795672 -227.491544)
		(end 309.521098 -227.21697)
		(width 0.18288)
		(layer "In4.Cu")
		(net "M_B_CPU0_SB_DQS_DP<0>")
	)
	(segment
		(start 310.190388 -227.491544)
		(end 309.795672 -227.491544)
		(width 0.18288)
		(layer "In4.Cu")
		(net "M_B_CPU0_SB_DQS_DP<0>")
	)
	(segment
		(start 336.287364 -235.46816)
		(end 336.272632 -235.459524)
		(width 0.088646)
		(layer "In4.Cu")
		(net "M_B_CPU0_SB_DQS_DP<0>")
	)
	(segment
		(start 299.440092 -228.9302)
		(end 299.178472 -229.19182)
		(width 0.18288)
		(layer "In4.Cu")
		(net "M_B_CPU0_SB_DQS_DP<0>")
	)
	(segment
		(start 301.634906 -228.156516)
		(end 301.13986 -228.651562)
		(width 0.18288)
		(layer "In4.Cu")
		(net "M_B_CPU0_SB_DQS_DP<0>")
	)
	(segment
		(start 330.752196 -235.480606)
		(end 330.692252 -235.54055)
		(width 0.088646)
		(layer "In4.Cu")
		(net "M_B_CPU0_SB_DQS_DP<0>")
	)
	(segment
		(start 295.185846 -228.485192)
		(end 294.904414 -228.766624)
		(width 0.18288)
		(layer "In4.Cu")
		(net "M_B_CPU0_SB_DQS_DP<0>")
	)
	(segment
		(start 339.344254 -235.343446)
		(end 339.287104 -235.336588)
		(width 0.088646)
		(layer "In4.Cu")
		(net "M_B_CPU0_SB_DQS_DP<0>")
	)
	(segment
		(start 330.692252 -235.54055)
		(end 330.648564 -235.54055)
		(width 0.088646)
		(layer "In4.Cu")
		(net "M_B_CPU0_SB_DQS_DP<0>")
	)
	(segment
		(start 298.57065 -228.955854)
		(end 298.077636 -228.955854)
		(width 0.18288)
		(layer "In4.Cu")
		(net "M_B_CPU0_SB_DQS_DP<0>")
	)
	(segment
		(start 313.59983 -228.897434)
		(end 313.015122 -228.897434)
		(width 0.18288)
		(layer "In4.Cu")
		(net "M_B_CPU0_SB_DQS_DP<0>")
	)
	(segment
		(start 311.329324 -227.211636)
		(end 310.470296 -227.211636)
		(width 0.18288)
		(layer "In4.Cu")
		(net "M_B_CPU0_SB_DQS_DP<0>")
	)
	(segment
		(start 306.873656 -226.958144)
		(end 306.30876 -226.958144)
		(width 0.18288)
		(layer "In4.Cu")
		(net "M_B_CPU0_SB_DQS_DP<0>")
	)
	(segment
		(start 308.329838 -226.569778)
		(end 307.262022 -226.569778)
		(width 0.18288)
		(layer "In4.Cu")
		(net "M_B_CPU0_SB_DQS_DP<0>")
	)
	(segment
		(start 338.151978 -235.459524)
		(end 338.152232 -235.459524)
		(width 0.088646)
		(layer "In4.Cu")
		(net "M_B_CPU0_SB_DQS_DP<0>")
	)
	(segment
		(start 297.37685 -228.255068)
		(end 295.740074 -228.255068)
		(width 0.18288)
		(layer "In4.Cu")
		(net "M_B_CPU0_SB_DQS_DP<0>")
	)
	(segment
		(start 299.440092 -228.808534)
		(end 299.440092 -228.9302)
		(width 0.18288)
		(layer "In4.Cu")
		(net "M_B_CPU0_SB_DQS_DP<0>")
	)
	(segment
		(start 309.521098 -227.21697)
		(end 308.97703 -227.21697)
		(width 0.18288)
		(layer "In4.Cu")
		(net "M_B_CPU0_SB_DQS_DP<0>")
	)
	(segment
		(start 313.894216 -229.19182)
		(end 313.59983 -228.897434)
		(width 0.18288)
		(layer "In4.Cu")
		(net "M_B_CPU0_SB_DQS_DP<0>")
	)
	(segment
		(start 314.555378 -228.899974)
		(end 314.263532 -229.19182)
		(width 0.18288)
		(layer "In4.Cu")
		(net "M_B_CPU0_SB_DQS_DP<0>")
	)
	(segment
		(start 295.50995 -228.485192)
		(end 295.185846 -228.485192)
		(width 0.18288)
		(layer "In4.Cu")
		(net "M_B_CPU0_SB_DQS_DP<0>")
	)
	(segment
		(start 337.227164 -235.46816)
		(end 337.212432 -235.459524)
		(width 0.088646)
		(layer "In4.Cu")
		(net "M_B_CPU0_SB_DQS_DP<0>")
	)
	(segment
		(start 298.806616 -229.19182)
		(end 298.57065 -228.955854)
		(width 0.18288)
		(layer "In4.Cu")
		(net "M_B_CPU0_SB_DQS_DP<0>")
	)
	(segment
		(start 334.407764 -235.46816)
		(end 334.393032 -235.459524)
		(width 0.088646)
		(layer "In4.Cu")
		(net "M_B_CPU0_SB_DQS_DP<0>")
	)
	(segment
		(start 313.015122 -228.897434)
		(end 311.329324 -227.211636)
		(width 0.18288)
		(layer "In4.Cu")
		(net "M_B_CPU0_SB_DQS_DP<0>")
	)
	(segment
		(start 335.347564 -235.46816)
		(end 335.332832 -235.459524)
		(width 0.088646)
		(layer "In4.Cu")
		(net "M_B_CPU0_SB_DQS_DP<0>")
	)
	(segment
		(start 339.287104 -235.336588)
		(end 339.282278 -235.339128)
		(width 0.088646)
		(layer "In4.Cu")
		(net "M_B_CPU0_SB_DQS_DP<0>")
	)
	(segment
		(start 322.02882 -235.54055)
		(end 315.388244 -228.899974)
		(width 0.18288)
		(layer "In4.Cu")
		(net "M_B_CPU0_SB_DQS_DP<0>")
	)
	(arc
		(start 332.528164 -235.46816)
		(mid 332.431304 -235.424131)
		(end 332.32598 -235.408978)
		(width 0.088646)
		(layer "In4.Cu")
		(net "M_B_CPU0_SB_DQS_DP<0>")
	)
	(arc
		(start 335.332832 -235.459524)
		(mid 335.145634 -235.409381)
		(end 334.958436 -235.459524)
		(width 0.088646)
		(layer "In4.Cu")
		(net "M_B_CPU0_SB_DQS_DP<0>")
	)
	(arc
		(start 336.272632 -235.459524)
		(mid 336.085434 -235.409381)
		(end 335.898236 -235.459524)
		(width 0.088646)
		(layer "In4.Cu")
		(net "M_B_CPU0_SB_DQS_DP<0>")
	)
	(arc
		(start 333.453232 -235.459524)
		(mid 333.266034 -235.409381)
		(end 333.078836 -235.459524)
		(width 0.088646)
		(layer "In4.Cu")
		(net "M_B_CPU0_SB_DQS_DP<0>")
	)
	(arc
		(start 333.078836 -235.459524)
		(mid 332.804637 -235.535359)
		(end 332.528164 -235.46816)
		(width 0.088646)
		(layer "In4.Cu")
		(net "M_B_CPU0_SB_DQS_DP<0>")
	)
	(arc
		(start 337.777836 -235.459524)
		(mid 337.503637 -235.535359)
		(end 337.227164 -235.46816)
		(width 0.088646)
		(layer "In4.Cu")
		(net "M_B_CPU0_SB_DQS_DP<0>")
	)
	(arc
		(start 338.152232 -235.459524)
		(mid 337.965034 -235.409381)
		(end 337.777836 -235.459524)
		(width 0.088646)
		(layer "In4.Cu")
		(net "M_B_CPU0_SB_DQS_DP<0>")
	)
	(arc
		(start 338.703158 -235.467906)
		(mid 338.426493 -235.535377)
		(end 338.151978 -235.459524)
		(width 0.088646)
		(layer "In4.Cu")
		(net "M_B_CPU0_SB_DQS_DP<0>")
	)
	(arc
		(start 334.018636 -235.459524)
		(mid 333.744437 -235.535359)
		(end 333.467964 -235.46816)
		(width 0.088646)
		(layer "In4.Cu")
		(net "M_B_CPU0_SB_DQS_DP<0>")
	)
	(arc
		(start 339.548724 -235.30179)
		(mid 339.449882 -235.3393)
		(end 339.344254 -235.343446)
		(width 0.088646)
		(layer "In4.Cu")
		(net "M_B_CPU0_SB_DQS_DP<0>")
	)
	(arc
		(start 334.393032 -235.459524)
		(mid 334.205834 -235.409381)
		(end 334.018636 -235.459524)
		(width 0.088646)
		(layer "In4.Cu")
		(net "M_B_CPU0_SB_DQS_DP<0>")
	)
	(arc
		(start 337.212432 -235.459524)
		(mid 337.025234 -235.409381)
		(end 336.838036 -235.459524)
		(width 0.088646)
		(layer "In4.Cu")
		(net "M_B_CPU0_SB_DQS_DP<0>")
	)
	(arc
		(start 336.838036 -235.459524)
		(mid 336.563837 -235.535359)
		(end 336.287364 -235.46816)
		(width 0.088646)
		(layer "In4.Cu")
		(net "M_B_CPU0_SB_DQS_DP<0>")
	)
	(arc
		(start 340.31428 -234.970066)
		(mid 340.138259 -234.992903)
		(end 339.97392 -235.059982)
		(width 0.088646)
		(layer "In4.Cu")
		(net "M_B_CPU0_SB_DQS_DP<0>")
	)
	(arc
		(start 335.898236 -235.459524)
		(mid 335.624037 -235.535359)
		(end 335.347564 -235.46816)
		(width 0.088646)
		(layer "In4.Cu")
		(net "M_B_CPU0_SB_DQS_DP<0>")
	)
	(arc
		(start 334.958436 -235.459524)
		(mid 334.684237 -235.535359)
		(end 334.407764 -235.46816)
		(width 0.088646)
		(layer "In4.Cu")
		(net "M_B_CPU0_SB_DQS_DP<0>")
	)
	(segment
		(start 291.556694 -237.691676)
		(end 289.243008 -237.691676)
		(width 0.1016)
		(layer "F.Cu")
		(net "M_B_CPU0_SB_DQS_DN<9>")
	)
	(segment
		(start 291.973254 -237.953042)
		(end 291.711888 -237.691676)
		(width 0.20066)
		(layer "F.Cu")
		(net "M_B_CPU0_SB_DQS_DN<9>")
	)
	(segment
		(start 289.243008 -237.691676)
		(end 289.23234 -237.681008)
		(width 0.101854)
		(layer "F.Cu")
		(net "M_B_CPU0_SB_DQS_DN<9>")
	)
	(segment
		(start 337.025234 -242.830604)
		(end 337.025234 -242.294918)
		(width 0.20066)
		(layer "F.Cu")
		(net "M_B_CPU0_SB_DQS_DN<9>")
	)
	(segment
		(start 286.804354 -237.266734)
		(end 286.255714 -237.266734)
		(width 0.20066)
		(layer "F.Cu")
		(net "M_B_CPU0_SB_DQS_DN<9>")
	)
	(segment
		(start 337.02498 -242.830858)
		(end 337.025234 -242.830604)
		(width 0.20066)
		(layer "F.Cu")
		(net "M_B_CPU0_SB_DQS_DN<9>")
	)
	(segment
		(start 292.58514 -237.527846)
		(end 292.159944 -237.953042)
		(width 0.20066)
		(layer "F.Cu")
		(net "M_B_CPU0_SB_DQS_DN<9>")
	)
	(segment
		(start 289.027362 -237.681008)
		(end 288.755328 -237.953042)
		(width 0.20066)
		(layer "F.Cu")
		(net "M_B_CPU0_SB_DQS_DN<9>")
	)
	(segment
		(start 292.159944 -237.953042)
		(end 291.973254 -237.953042)
		(width 0.20066)
		(layer "F.Cu")
		(net "M_B_CPU0_SB_DQS_DN<9>")
	)
	(segment
		(start 289.231578 -237.681008)
		(end 289.027362 -237.681008)
		(width 0.20066)
		(layer "F.Cu")
		(net "M_B_CPU0_SB_DQS_DN<9>")
	)
	(segment
		(start 293.799514 -237.266734)
		(end 293.252906 -237.266734)
		(width 0.20066)
		(layer "F.Cu")
		(net "M_B_CPU0_SB_DQS_DN<9>")
	)
	(segment
		(start 287.579308 -237.527846)
		(end 287.065466 -237.527846)
		(width 0.20066)
		(layer "F.Cu")
		(net "M_B_CPU0_SB_DQS_DN<9>")
	)
	(segment
		(start 293.252906 -237.266734)
		(end 292.991794 -237.527846)
		(width 0.20066)
		(layer "F.Cu")
		(net "M_B_CPU0_SB_DQS_DN<9>")
	)
	(segment
		(start 291.711888 -237.691676)
		(end 291.556694 -237.691676)
		(width 0.20066)
		(layer "F.Cu")
		(net "M_B_CPU0_SB_DQS_DN<9>")
	)
	(segment
		(start 292.991794 -237.527846)
		(end 292.58514 -237.527846)
		(width 0.20066)
		(layer "F.Cu")
		(net "M_B_CPU0_SB_DQS_DN<9>")
	)
	(segment
		(start 288.755328 -237.953042)
		(end 288.215324 -237.953042)
		(width 0.20066)
		(layer "F.Cu")
		(net "M_B_CPU0_SB_DQS_DN<9>")
	)
	(segment
		(start 289.23234 -237.681008)
		(end 289.231578 -237.681008)
		(width 0.101854)
		(layer "F.Cu")
		(net "M_B_CPU0_SB_DQS_DN<9>")
	)
	(segment
		(start 287.065466 -237.527846)
		(end 286.804354 -237.266734)
		(width 0.20066)
		(layer "F.Cu")
		(net "M_B_CPU0_SB_DQS_DN<9>")
	)
	(segment
		(start 294.904414 -237.266734)
		(end 293.799514 -237.266734)
		(width 0.20066)
		(layer "F.Cu")
		(net "M_B_CPU0_SB_DQS_DN<9>")
	)
	(segment
		(start 288.215324 -237.953042)
		(end 287.579308 -237.527846)
		(width 0.20066)
		(layer "F.Cu")
		(net "M_B_CPU0_SB_DQS_DN<9>")
	)
	(segment
		(start 297.339512 -235.408978)
		(end 297.079162 -235.669328)
		(width 0.18288)
		(layer "In2.Cu")
		(net "M_B_CPU0_SB_DQS_DN<9>")
	)
	(segment
		(start 302.288194 -234.959144)
		(end 302.123602 -234.794552)
		(width 0.18288)
		(layer "In2.Cu")
		(net "M_B_CPU0_SB_DQS_DN<9>")
	)
	(segment
		(start 304.79746 -235.48721)
		(end 304.587402 -235.697268)
		(width 0.18288)
		(layer "In2.Cu")
		(net "M_B_CPU0_SB_DQS_DN<9>")
	)
	(segment
		(start 331.064108 -241.92611)
		(end 331.004164 -241.866166)
		(width 0.088646)
		(layer "In2.Cu")
		(net "M_B_CPU0_SB_DQS_DN<9>")
	)
	(segment
		(start 312.014108 -235.85297)
		(end 311.813956 -236.053122)
		(width 0.16002)
		(layer "In2.Cu")
		(net "M_B_CPU0_SB_DQS_DN<9>")
	)
	(segment
		(start 335.504282 -241.858038)
		(end 335.49463 -241.84991)
		(width 0.088646)
		(layer "In2.Cu")
		(net "M_B_CPU0_SB_DQS_DN<9>")
	)
	(segment
		(start 306.416456 -235.837222)
		(end 306.388262 -235.809028)
		(width 0.16002)
		(layer "In2.Cu")
		(net "M_B_CPU0_SB_DQS_DN<9>")
	)
	(segment
		(start 303.013364 -235.68406)
		(end 302.560482 -235.231432)
		(width 0.18288)
		(layer "In2.Cu")
		(net "M_B_CPU0_SB_DQS_DN<9>")
	)
	(segment
		(start 307.327046 -236.23397)
		(end 306.813204 -236.23397)
		(width 0.18288)
		(layer "In2.Cu")
		(net "M_B_CPU0_SB_DQS_DN<9>")
	)
	(segment
		(start 334.877664 -241.796824)
		(end 334.862932 -241.80546)
		(width 0.088646)
		(layer "In2.Cu")
		(net "M_B_CPU0_SB_DQS_DN<9>")
	)
	(segment
		(start 306.632356 -236.053122)
		(end 306.616608 -236.053122)
		(width 0.16002)
		(layer "In2.Cu")
		(net "M_B_CPU0_SB_DQS_DN<9>")
	)
	(segment
		(start 303.923446 -236.06125)
		(end 303.013364 -235.68406)
		(width 0.18288)
		(layer "In2.Cu")
		(net "M_B_CPU0_SB_DQS_DN<9>")
	)
	(segment
		(start 308.266084 -236.232954)
		(end 307.991256 -235.958126)
		(width 0.18288)
		(layer "In2.Cu")
		(net "M_B_CPU0_SB_DQS_DN<9>")
	)
	(segment
		(start 307.991256 -235.958126)
		(end 307.60289 -235.958126)
		(width 0.18288)
		(layer "In2.Cu")
		(net "M_B_CPU0_SB_DQS_DN<9>")
	)
	(segment
		(start 296.53738 -236.21111)
		(end 296.53738 -236.521498)
		(width 0.18288)
		(layer "In2.Cu")
		(net "M_B_CPU0_SB_DQS_DN<9>")
	)
	(segment
		(start 304.22342 -236.06125)
		(end 303.923446 -236.06125)
		(width 0.18288)
		(layer "In2.Cu")
		(net "M_B_CPU0_SB_DQS_DN<9>")
	)
	(segment
		(start 300.126146 -235.231432)
		(end 299.941742 -235.415836)
		(width 0.18288)
		(layer "In2.Cu")
		(net "M_B_CPU0_SB_DQS_DN<9>")
	)
	(segment
		(start 300.398434 -234.959144)
		(end 300.37024 -234.987338)
		(width 0.16002)
		(layer "In2.Cu")
		(net "M_B_CPU0_SB_DQS_DN<9>")
	)
	(segment
		(start 336.301842 -241.987578)
		(end 336.272632 -241.97056)
		(width 0.088646)
		(layer "In2.Cu")
		(net "M_B_CPU0_SB_DQS_DN<9>")
	)
	(segment
		(start 300.170088 -235.203238)
		(end 300.15434 -235.203238)
		(width 0.16002)
		(layer "In2.Cu")
		(net "M_B_CPU0_SB_DQS_DN<9>")
	)
	(segment
		(start 298.540932 -235.408978)
		(end 297.339512 -235.408978)
		(width 0.18288)
		(layer "In2.Cu")
		(net "M_B_CPU0_SB_DQS_DN<9>")
	)
	(segment
		(start 304.343308 -235.941362)
		(end 304.315114 -235.969556)
		(width 0.16002)
		(layer "In2.Cu")
		(net "M_B_CPU0_SB_DQS_DN<9>")
	)
	(segment
		(start 314.145676 -236.022642)
		(end 314.129928 -236.022642)
		(width 0.16002)
		(layer "In2.Cu")
		(net "M_B_CPU0_SB_DQS_DN<9>")
	)
	(segment
		(start 333.548736 -241.80546)
		(end 333.548482 -241.80546)
		(width 0.088646)
		(layer "In2.Cu")
		(net "M_B_CPU0_SB_DQS_DN<9>")
	)
	(segment
		(start 302.316388 -234.987338)
		(end 302.288194 -234.959144)
		(width 0.16002)
		(layer "In2.Cu")
		(net "M_B_CPU0_SB_DQS_DN<9>")
	)
	(segment
		(start 304.359056 -235.941362)
		(end 304.343308 -235.941362)
		(width 0.16002)
		(layer "In2.Cu")
		(net "M_B_CPU0_SB_DQS_DN<9>")
	)
	(segment
		(start 298.80814 -235.14177)
		(end 298.540932 -235.408978)
		(width 0.18288)
		(layer "In2.Cu")
		(net "M_B_CPU0_SB_DQS_DN<9>")
	)
	(segment
		(start 306.416456 -235.85297)
		(end 306.416456 -235.837222)
		(width 0.16002)
		(layer "In2.Cu")
		(net "M_B_CPU0_SB_DQS_DN<9>")
	)
	(segment
		(start 310.02859 -235.958126)
		(end 309.753762 -236.232954)
		(width 0.18288)
		(layer "In2.Cu")
		(net "M_B_CPU0_SB_DQS_DN<9>")
	)
	(segment
		(start 311.618376 -236.232954)
		(end 310.691784 -236.232954)
		(width 0.18288)
		(layer "In2.Cu")
		(net "M_B_CPU0_SB_DQS_DN<9>")
	)
	(segment
		(start 299.941742 -235.415836)
		(end 299.464476 -235.415836)
		(width 0.18288)
		(layer "In2.Cu")
		(net "M_B_CPU0_SB_DQS_DN<9>")
	)
	(segment
		(start 311.770014 -236.081316)
		(end 311.618376 -236.232954)
		(width 0.18288)
		(layer "In2.Cu")
		(net "M_B_CPU0_SB_DQS_DN<9>")
	)
	(segment
		(start 332.01356 -241.729768)
		(end 331.817218 -241.92611)
		(width 0.088646)
		(layer "In2.Cu")
		(net "M_B_CPU0_SB_DQS_DN<9>")
	)
	(segment
		(start 335.49463 -241.84991)
		(end 335.4705 -241.829844)
		(width 0.088646)
		(layer "In2.Cu")
		(net "M_B_CPU0_SB_DQS_DN<9>")
	)
	(segment
		(start 295.560242 -237.498636)
		(end 295.136316 -237.498636)
		(width 0.18288)
		(layer "In2.Cu")
		(net "M_B_CPU0_SB_DQS_DN<9>")
	)
	(segment
		(start 313.750198 -235.627164)
		(end 312.224166 -235.627164)
		(width 0.18288)
		(layer "In2.Cu")
		(net "M_B_CPU0_SB_DQS_DN<9>")
	)
	(segment
		(start 306.616608 -236.053122)
		(end 306.416456 -235.85297)
		(width 0.16002)
		(layer "In2.Cu")
		(net "M_B_CPU0_SB_DQS_DN<9>")
	)
	(segment
		(start 332.326234 -241.729768)
		(end 332.01356 -241.729768)
		(width 0.088646)
		(layer "In2.Cu")
		(net "M_B_CPU0_SB_DQS_DN<9>")
	)
	(segment
		(start 315.120782 -236.386878)
		(end 314.615068 -236.20857)
		(width 0.18288)
		(layer "In2.Cu")
		(net "M_B_CPU0_SB_DQS_DN<9>")
	)
	(segment
		(start 311.798208 -236.053122)
		(end 311.770014 -236.081316)
		(width 0.16002)
		(layer "In2.Cu")
		(net "M_B_CPU0_SB_DQS_DN<9>")
	)
	(segment
		(start 314.129928 -236.022642)
		(end 313.929776 -235.82249)
		(width 0.16002)
		(layer "In2.Cu")
		(net "M_B_CPU0_SB_DQS_DN<9>")
	)
	(segment
		(start 296.806874 -235.941616)
		(end 296.53738 -236.21111)
		(width 0.18288)
		(layer "In2.Cu")
		(net "M_B_CPU0_SB_DQS_DN<9>")
	)
	(segment
		(start 306.388262 -235.809028)
		(end 306.066444 -235.48721)
		(width 0.18288)
		(layer "In2.Cu")
		(net "M_B_CPU0_SB_DQS_DN<9>")
	)
	(segment
		(start 331.817218 -241.92611)
		(end 331.064108 -241.92611)
		(width 0.088646)
		(layer "In2.Cu")
		(net "M_B_CPU0_SB_DQS_DN<9>")
	)
	(segment
		(start 306.066444 -235.48721)
		(end 304.79746 -235.48721)
		(width 0.18288)
		(layer "In2.Cu")
		(net "M_B_CPU0_SB_DQS_DN<9>")
	)
	(segment
		(start 297.050968 -235.71327)
		(end 296.850816 -235.913422)
		(width 0.16002)
		(layer "In2.Cu")
		(net "M_B_CPU0_SB_DQS_DN<9>")
	)
	(segment
		(start 311.813956 -236.053122)
		(end 311.798208 -236.053122)
		(width 0.16002)
		(layer "In2.Cu")
		(net "M_B_CPU0_SB_DQS_DN<9>")
	)
	(segment
		(start 335.4705 -241.829844)
		(end 335.428336 -241.80546)
		(width 0.088646)
		(layer "In2.Cu")
		(net "M_B_CPU0_SB_DQS_DN<9>")
	)
	(segment
		(start 304.559208 -235.74121)
		(end 304.359056 -235.941362)
		(width 0.16002)
		(layer "In2.Cu")
		(net "M_B_CPU0_SB_DQS_DN<9>")
	)
	(segment
		(start 302.560482 -235.231432)
		(end 302.532288 -235.203238)
		(width 0.16002)
		(layer "In2.Cu")
		(net "M_B_CPU0_SB_DQS_DN<9>")
	)
	(segment
		(start 304.559208 -235.725462)
		(end 304.559208 -235.74121)
		(width 0.16002)
		(layer "In2.Cu")
		(net "M_B_CPU0_SB_DQS_DN<9>")
	)
	(segment
		(start 296.53738 -236.521498)
		(end 295.560242 -237.498636)
		(width 0.18288)
		(layer "In2.Cu")
		(net "M_B_CPU0_SB_DQS_DN<9>")
	)
	(segment
		(start 314.331604 -236.20857)
		(end 314.17387 -236.050836)
		(width 0.18288)
		(layer "In2.Cu")
		(net "M_B_CPU0_SB_DQS_DN<9>")
	)
	(segment
		(start 307.60289 -235.958126)
		(end 307.327046 -236.23397)
		(width 0.18288)
		(layer "In2.Cu")
		(net "M_B_CPU0_SB_DQS_DN<9>")
	)
	(segment
		(start 314.17387 -236.050836)
		(end 314.145676 -236.022642)
		(width 0.16002)
		(layer "In2.Cu")
		(net "M_B_CPU0_SB_DQS_DN<9>")
	)
	(segment
		(start 304.315114 -235.969556)
		(end 304.22342 -236.06125)
		(width 0.18288)
		(layer "In2.Cu")
		(net "M_B_CPU0_SB_DQS_DN<9>")
	)
	(segment
		(start 312.224166 -235.627164)
		(end 312.042302 -235.809028)
		(width 0.18288)
		(layer "In2.Cu")
		(net "M_B_CPU0_SB_DQS_DN<9>")
	)
	(segment
		(start 302.532288 -235.203238)
		(end 302.51654 -235.203238)
		(width 0.16002)
		(layer "In2.Cu")
		(net "M_B_CPU0_SB_DQS_DN<9>")
	)
	(segment
		(start 302.51654 -235.203238)
		(end 302.316388 -235.003086)
		(width 0.16002)
		(layer "In2.Cu")
		(net "M_B_CPU0_SB_DQS_DN<9>")
	)
	(segment
		(start 312.014108 -235.837222)
		(end 312.014108 -235.85297)
		(width 0.16002)
		(layer "In2.Cu")
		(net "M_B_CPU0_SB_DQS_DN<9>")
	)
	(segment
		(start 302.123602 -234.794552)
		(end 300.563026 -234.794552)
		(width 0.18288)
		(layer "In2.Cu")
		(net "M_B_CPU0_SB_DQS_DN<9>")
	)
	(segment
		(start 302.316388 -235.003086)
		(end 302.316388 -234.987338)
		(width 0.16002)
		(layer "In2.Cu")
		(net "M_B_CPU0_SB_DQS_DN<9>")
	)
	(segment
		(start 313.929776 -235.806742)
		(end 313.901582 -235.778548)
		(width 0.16002)
		(layer "In2.Cu")
		(net "M_B_CPU0_SB_DQS_DN<9>")
	)
	(segment
		(start 300.37024 -235.003086)
		(end 300.170088 -235.203238)
		(width 0.16002)
		(layer "In2.Cu")
		(net "M_B_CPU0_SB_DQS_DN<9>")
	)
	(segment
		(start 300.563026 -234.794552)
		(end 300.398434 -234.959144)
		(width 0.18288)
		(layer "In2.Cu")
		(net "M_B_CPU0_SB_DQS_DN<9>")
	)
	(segment
		(start 337.01228 -242.281964)
		(end 336.301842 -241.987578)
		(width 0.088646)
		(layer "In2.Cu")
		(net "M_B_CPU0_SB_DQS_DN<9>")
	)
	(segment
		(start 300.15434 -235.203238)
		(end 300.126146 -235.231432)
		(width 0.16002)
		(layer "In2.Cu")
		(net "M_B_CPU0_SB_DQS_DN<9>")
	)
	(segment
		(start 310.691784 -236.232954)
		(end 310.416956 -235.958126)
		(width 0.18288)
		(layer "In2.Cu")
		(net "M_B_CPU0_SB_DQS_DN<9>")
	)
	(segment
		(start 296.835068 -235.913422)
		(end 296.806874 -235.941616)
		(width 0.16002)
		(layer "In2.Cu")
		(net "M_B_CPU0_SB_DQS_DN<9>")
	)
	(segment
		(start 331.004164 -241.866166)
		(end 323.434202 -241.866166)
		(width 0.18288)
		(layer "In2.Cu")
		(net "M_B_CPU0_SB_DQS_DN<9>")
	)
	(segment
		(start 306.813204 -236.23397)
		(end 306.66055 -236.081316)
		(width 0.18288)
		(layer "In2.Cu")
		(net "M_B_CPU0_SB_DQS_DN<9>")
	)
	(segment
		(start 296.850816 -235.913422)
		(end 296.835068 -235.913422)
		(width 0.16002)
		(layer "In2.Cu")
		(net "M_B_CPU0_SB_DQS_DN<9>")
	)
	(segment
		(start 306.66055 -236.081316)
		(end 306.632356 -236.053122)
		(width 0.16002)
		(layer "In2.Cu")
		(net "M_B_CPU0_SB_DQS_DN<9>")
	)
	(segment
		(start 297.050968 -235.697522)
		(end 297.050968 -235.71327)
		(width 0.16002)
		(layer "In2.Cu")
		(net "M_B_CPU0_SB_DQS_DN<9>")
	)
	(segment
		(start 335.50479 -241.858292)
		(end 335.504282 -241.858038)
		(width 0.088646)
		(layer "In2.Cu")
		(net "M_B_CPU0_SB_DQS_DN<9>")
	)
	(segment
		(start 295.136316 -237.498636)
		(end 294.904414 -237.266734)
		(width 0.18288)
		(layer "In2.Cu")
		(net "M_B_CPU0_SB_DQS_DN<9>")
	)
	(segment
		(start 336.013044 -241.900456)
		(end 335.622138 -241.900456)
		(width 0.088646)
		(layer "In2.Cu")
		(net "M_B_CPU0_SB_DQS_DN<9>")
	)
	(segment
		(start 304.587402 -235.697268)
		(end 304.559208 -235.725462)
		(width 0.16002)
		(layer "In2.Cu")
		(net "M_B_CPU0_SB_DQS_DN<9>")
	)
	(segment
		(start 299.19041 -235.14177)
		(end 298.80814 -235.14177)
		(width 0.18288)
		(layer "In2.Cu")
		(net "M_B_CPU0_SB_DQS_DN<9>")
	)
	(segment
		(start 300.37024 -234.987338)
		(end 300.37024 -235.003086)
		(width 0.16002)
		(layer "In2.Cu")
		(net "M_B_CPU0_SB_DQS_DN<9>")
	)
	(segment
		(start 314.615068 -236.20857)
		(end 314.331604 -236.20857)
		(width 0.18288)
		(layer "In2.Cu")
		(net "M_B_CPU0_SB_DQS_DN<9>")
	)
	(segment
		(start 310.416956 -235.958126)
		(end 310.02859 -235.958126)
		(width 0.18288)
		(layer "In2.Cu")
		(net "M_B_CPU0_SB_DQS_DN<9>")
	)
	(segment
		(start 309.753762 -236.232954)
		(end 308.266084 -236.232954)
		(width 0.18288)
		(layer "In2.Cu")
		(net "M_B_CPU0_SB_DQS_DN<9>")
	)
	(segment
		(start 337.025234 -242.294918)
		(end 337.01228 -242.281964)
		(width 0.088646)
		(layer "In2.Cu")
		(net "M_B_CPU0_SB_DQS_DN<9>")
	)
	(segment
		(start 313.901582 -235.778548)
		(end 313.750198 -235.627164)
		(width 0.18288)
		(layer "In2.Cu")
		(net "M_B_CPU0_SB_DQS_DN<9>")
	)
	(segment
		(start 323.434202 -241.866166)
		(end 319.961768 -238.393732)
		(width 0.18288)
		(layer "In2.Cu")
		(net "M_B_CPU0_SB_DQS_DN<9>")
	)
	(segment
		(start 299.464476 -235.415836)
		(end 299.19041 -235.14177)
		(width 0.18288)
		(layer "In2.Cu")
		(net "M_B_CPU0_SB_DQS_DN<9>")
	)
	(segment
		(start 319.961768 -238.393732)
		(end 315.120782 -236.386878)
		(width 0.18288)
		(layer "In2.Cu")
		(net "M_B_CPU0_SB_DQS_DN<9>")
	)
	(segment
		(start 297.079162 -235.669328)
		(end 297.050968 -235.697522)
		(width 0.16002)
		(layer "In2.Cu")
		(net "M_B_CPU0_SB_DQS_DN<9>")
	)
	(segment
		(start 312.042302 -235.809028)
		(end 312.014108 -235.837222)
		(width 0.16002)
		(layer "In2.Cu")
		(net "M_B_CPU0_SB_DQS_DN<9>")
	)
	(segment
		(start 313.929776 -235.82249)
		(end 313.929776 -235.806742)
		(width 0.16002)
		(layer "In2.Cu")
		(net "M_B_CPU0_SB_DQS_DN<9>")
	)
	(arc
		(start 333.923132 -241.80546)
		(mid 333.735934 -241.855603)
		(end 333.548736 -241.80546)
		(width 0.088646)
		(layer "In2.Cu")
		(net "M_B_CPU0_SB_DQS_DN<9>")
	)
	(arc
		(start 336.272632 -241.97056)
		(mid 336.147489 -241.918286)
		(end 336.013044 -241.900456)
		(width 0.088646)
		(layer "In2.Cu")
		(net "M_B_CPU0_SB_DQS_DN<9>")
	)
	(arc
		(start 334.488536 -241.80546)
		(mid 334.205834 -241.729684)
		(end 333.923132 -241.80546)
		(width 0.088646)
		(layer "In2.Cu")
		(net "M_B_CPU0_SB_DQS_DN<9>")
	)
	(arc
		(start 332.608682 -241.80546)
		(mid 332.472436 -241.749051)
		(end 332.326234 -241.729768)
		(width 0.088646)
		(layer "In2.Cu")
		(net "M_B_CPU0_SB_DQS_DN<9>")
	)
	(arc
		(start 335.428336 -241.80546)
		(mid 335.154137 -241.729625)
		(end 334.877664 -241.796824)
		(width 0.088646)
		(layer "In2.Cu")
		(net "M_B_CPU0_SB_DQS_DN<9>")
	)
	(arc
		(start 333.548482 -241.80546)
		(mid 333.26578 -241.729684)
		(end 332.983078 -241.80546)
		(width 0.088646)
		(layer "In2.Cu")
		(net "M_B_CPU0_SB_DQS_DN<9>")
	)
	(arc
		(start 334.862932 -241.80546)
		(mid 334.675734 -241.855603)
		(end 334.488536 -241.80546)
		(width 0.088646)
		(layer "In2.Cu")
		(net "M_B_CPU0_SB_DQS_DN<9>")
	)
	(arc
		(start 332.983078 -241.80546)
		(mid 332.79588 -241.855603)
		(end 332.608682 -241.80546)
		(width 0.088646)
		(layer "In2.Cu")
		(net "M_B_CPU0_SB_DQS_DN<9>")
	)
	(arc
		(start 335.622138 -241.900456)
		(mid 335.559781 -241.889609)
		(end 335.50479 -241.858292)
		(width 0.088646)
		(layer "In2.Cu")
		(net "M_B_CPU0_SB_DQS_DN<9>")
	)
	(segment
		(start 295.000426 -199.441816)
		(end 292.92296 -199.441816)
		(width 0.1016)
		(layer "F.Cu")
		(net "M_B_CPU0_SB_DQS_DN<8>")
	)
	(segment
		(start 292.92296 -199.441816)
		(end 292.683184 -199.441816)
		(width 0.101854)
		(layer "F.Cu")
		(net "M_B_CPU0_SB_DQS_DN<8>")
	)
	(segment
		(start 292.223952 -199.183244)
		(end 291.984176 -199.183244)
		(width 0.20066)
		(layer "F.Cu")
		(net "M_B_CPU0_SB_DQS_DN<8>")
	)
	(segment
		(start 290.82746 -199.866758)
		(end 290.355782 -199.866758)
		(width 0.20066)
		(layer "F.Cu")
		(net "M_B_CPU0_SB_DQS_DN<8>")
	)
	(segment
		(start 297.409108 -199.866758)
		(end 297.147996 -199.605646)
		(width 0.20066)
		(layer "F.Cu")
		(net "M_B_CPU0_SB_DQS_DN<8>")
	)
	(segment
		(start 292.683184 -199.441816)
		(end 292.67531 -199.44969)
		(width 0.101854)
		(layer "F.Cu")
		(net "M_B_CPU0_SB_DQS_DN<8>")
	)
	(segment
		(start 295.142666 -199.441816)
		(end 295.000426 -199.441816)
		(width 0.20066)
		(layer "F.Cu")
		(net "M_B_CPU0_SB_DQS_DN<8>")
	)
	(segment
		(start 334.675734 -225.739198)
		(end 334.675734 -225.203258)
		(width 0.20066)
		(layer "F.Cu")
		(net "M_B_CPU0_SB_DQS_DN<8>")
	)
	(segment
		(start 295.403778 -199.180704)
		(end 295.142666 -199.441816)
		(width 0.20066)
		(layer "F.Cu")
		(net "M_B_CPU0_SB_DQS_DN<8>")
	)
	(segment
		(start 296.444416 -199.605646)
		(end 295.8084 -199.180704)
		(width 0.20066)
		(layer "F.Cu")
		(net "M_B_CPU0_SB_DQS_DN<8>")
	)
	(segment
		(start 295.8084 -199.180704)
		(end 295.403778 -199.180704)
		(width 0.20066)
		(layer "F.Cu")
		(net "M_B_CPU0_SB_DQS_DN<8>")
	)
	(segment
		(start 299.004482 -199.866758)
		(end 297.899582 -199.866758)
		(width 0.20066)
		(layer "F.Cu")
		(net "M_B_CPU0_SB_DQS_DN<8>")
	)
	(segment
		(start 291.561774 -199.605646)
		(end 291.088572 -199.605646)
		(width 0.20066)
		(layer "F.Cu")
		(net "M_B_CPU0_SB_DQS_DN<8>")
	)
	(segment
		(start 292.67531 -199.44969)
		(end 292.490398 -199.44969)
		(width 0.20066)
		(layer "F.Cu")
		(net "M_B_CPU0_SB_DQS_DN<8>")
	)
	(segment
		(start 297.899582 -199.866758)
		(end 297.409108 -199.866758)
		(width 0.20066)
		(layer "F.Cu")
		(net "M_B_CPU0_SB_DQS_DN<8>")
	)
	(segment
		(start 297.147996 -199.605646)
		(end 296.444416 -199.605646)
		(width 0.20066)
		(layer "F.Cu")
		(net "M_B_CPU0_SB_DQS_DN<8>")
	)
	(segment
		(start 291.984176 -199.183244)
		(end 291.561774 -199.605646)
		(width 0.20066)
		(layer "F.Cu")
		(net "M_B_CPU0_SB_DQS_DN<8>")
	)
	(segment
		(start 291.088572 -199.605646)
		(end 290.82746 -199.866758)
		(width 0.20066)
		(layer "F.Cu")
		(net "M_B_CPU0_SB_DQS_DN<8>")
	)
	(segment
		(start 292.490398 -199.44969)
		(end 292.223952 -199.183244)
		(width 0.20066)
		(layer "F.Cu")
		(net "M_B_CPU0_SB_DQS_DN<8>")
	)
	(segment
		(start 303.060862 -199.805798)
		(end 299.81017 -199.805798)
		(width 0.18288)
		(layer "In4.Cu")
		(net "M_B_CPU0_SB_DQS_DN<8>")
	)
	(segment
		(start 310.997346 -199.00011)
		(end 310.58866 -198.591424)
		(width 0.18288)
		(layer "In4.Cu")
		(net "M_B_CPU0_SB_DQS_DN<8>")
	)
	(segment
		(start 328.765408 -222.574104)
		(end 324.668896 -218.477592)
		(width 0.18288)
		(layer "In4.Cu")
		(net "M_B_CPU0_SB_DQS_DN<8>")
	)
	(segment
		(start 309.114444 -198.715884)
		(end 308.565804 -198.715884)
		(width 0.18288)
		(layer "In4.Cu")
		(net "M_B_CPU0_SB_DQS_DN<8>")
	)
	(segment
		(start 331.738732 -223.317816)
		(end 331.738732 -223.197166)
		(width 0.088646)
		(layer "In4.Cu")
		(net "M_B_CPU0_SB_DQS_DN<8>")
	)
	(segment
		(start 324.668896 -218.477592)
		(end 319.168272 -205.13421)
		(width 0.18288)
		(layer "In4.Cu")
		(net "M_B_CPU0_SB_DQS_DN<8>")
	)
	(segment
		(start 310.58866 -198.591424)
		(end 309.238904 -198.591424)
		(width 0.18288)
		(layer "In4.Cu")
		(net "M_B_CPU0_SB_DQS_DN<8>")
	)
	(segment
		(start 311.687972 -199.00011)
		(end 310.997346 -199.00011)
		(width 0.18288)
		(layer "In4.Cu")
		(net "M_B_CPU0_SB_DQS_DN<8>")
	)
	(segment
		(start 334.675734 -225.203258)
		(end 334.988408 -225.203258)
		(width 0.088646)
		(layer "In4.Cu")
		(net "M_B_CPU0_SB_DQS_DN<8>")
	)
	(segment
		(start 330.671932 -222.574104)
		(end 330.648564 -222.574104)
		(width 0.088646)
		(layer "In4.Cu")
		(net "M_B_CPU0_SB_DQS_DN<8>")
	)
	(segment
		(start 331.055726 -222.51416)
		(end 330.731876 -222.51416)
		(width 0.088646)
		(layer "In4.Cu")
		(net "M_B_CPU0_SB_DQS_DN<8>")
	)
	(segment
		(start 308.441344 -198.591424)
		(end 307.37556 -198.591424)
		(width 0.18288)
		(layer "In4.Cu")
		(net "M_B_CPU0_SB_DQS_DN<8>")
	)
	(segment
		(start 332.98384 -224.8789)
		(end 332.983332 -224.8789)
		(width 0.088646)
		(layer "In4.Cu")
		(net "M_B_CPU0_SB_DQS_DN<8>")
	)
	(segment
		(start 319.168272 -205.13421)
		(end 313.034172 -199.00011)
		(width 0.18288)
		(layer "In4.Cu")
		(net "M_B_CPU0_SB_DQS_DN<8>")
	)
	(segment
		(start 312.361072 -199.12457)
		(end 311.812432 -199.12457)
		(width 0.18288)
		(layer "In4.Cu")
		(net "M_B_CPU0_SB_DQS_DN<8>")
	)
	(segment
		(start 334.988408 -225.203258)
		(end 335.045812 -225.145854)
		(width 0.088646)
		(layer "In4.Cu")
		(net "M_B_CPU0_SB_DQS_DN<8>")
	)
	(segment
		(start 307.026564 -198.94042)
		(end 303.92624 -198.94042)
		(width 0.18288)
		(layer "In4.Cu")
		(net "M_B_CPU0_SB_DQS_DN<8>")
	)
	(segment
		(start 334.488536 -224.878646)
		(end 334.488536 -224.8789)
		(width 0.088646)
		(layer "In4.Cu")
		(net "M_B_CPU0_SB_DQS_DN<8>")
	)
	(segment
		(start 332.98257 -224.878392)
		(end 332.977236 -224.875344)
		(width 0.088646)
		(layer "In4.Cu")
		(net "M_B_CPU0_SB_DQS_DN<8>")
	)
	(segment
		(start 299.277278 -199.593962)
		(end 299.004482 -199.866758)
		(width 0.18288)
		(layer "In4.Cu")
		(net "M_B_CPU0_SB_DQS_DN<8>")
	)
	(segment
		(start 313.034172 -199.00011)
		(end 312.485532 -199.00011)
		(width 0.18288)
		(layer "In4.Cu")
		(net "M_B_CPU0_SB_DQS_DN<8>")
	)
	(segment
		(start 307.37556 -198.591424)
		(end 307.026564 -198.94042)
		(width 0.18288)
		(layer "In4.Cu")
		(net "M_B_CPU0_SB_DQS_DN<8>")
	)
	(segment
		(start 330.731876 -222.51416)
		(end 330.671932 -222.574104)
		(width 0.088646)
		(layer "In4.Cu")
		(net "M_B_CPU0_SB_DQS_DN<8>")
	)
	(segment
		(start 333.548736 -224.8789)
		(end 333.547974 -224.878646)
		(width 0.088646)
		(layer "In4.Cu")
		(net "M_B_CPU0_SB_DQS_DN<8>")
	)
	(segment
		(start 332.396846 -223.976184)
		(end 332.396338 -223.975422)
		(width 0.088646)
		(layer "In4.Cu")
		(net "M_B_CPU0_SB_DQS_DN<8>")
	)
	(segment
		(start 330.648564 -222.574104)
		(end 328.765408 -222.574104)
		(width 0.18288)
		(layer "In4.Cu")
		(net "M_B_CPU0_SB_DQS_DN<8>")
	)
	(segment
		(start 332.396338 -223.975422)
		(end 331.738732 -223.317816)
		(width 0.088646)
		(layer "In4.Cu")
		(net "M_B_CPU0_SB_DQS_DN<8>")
	)
	(segment
		(start 309.238904 -198.591424)
		(end 309.114444 -198.715884)
		(width 0.18288)
		(layer "In4.Cu")
		(net "M_B_CPU0_SB_DQS_DN<8>")
	)
	(segment
		(start 332.983332 -224.8789)
		(end 332.98257 -224.878392)
		(width 0.088646)
		(layer "In4.Cu")
		(net "M_B_CPU0_SB_DQS_DN<8>")
	)
	(segment
		(start 308.565804 -198.715884)
		(end 308.441344 -198.591424)
		(width 0.18288)
		(layer "In4.Cu")
		(net "M_B_CPU0_SB_DQS_DN<8>")
	)
	(segment
		(start 311.812432 -199.12457)
		(end 311.687972 -199.00011)
		(width 0.18288)
		(layer "In4.Cu")
		(net "M_B_CPU0_SB_DQS_DN<8>")
	)
	(segment
		(start 312.485532 -199.00011)
		(end 312.361072 -199.12457)
		(width 0.18288)
		(layer "In4.Cu")
		(net "M_B_CPU0_SB_DQS_DN<8>")
	)
	(segment
		(start 303.92624 -198.94042)
		(end 303.060862 -199.805798)
		(width 0.18288)
		(layer "In4.Cu")
		(net "M_B_CPU0_SB_DQS_DN<8>")
	)
	(segment
		(start 299.598334 -199.593962)
		(end 299.277278 -199.593962)
		(width 0.18288)
		(layer "In4.Cu")
		(net "M_B_CPU0_SB_DQS_DN<8>")
	)
	(segment
		(start 331.738732 -223.197166)
		(end 331.055726 -222.51416)
		(width 0.088646)
		(layer "In4.Cu")
		(net "M_B_CPU0_SB_DQS_DN<8>")
	)
	(segment
		(start 299.81017 -199.805798)
		(end 299.598334 -199.593962)
		(width 0.18288)
		(layer "In4.Cu")
		(net "M_B_CPU0_SB_DQS_DN<8>")
	)
	(arc
		(start 334.488536 -224.8789)
		(mid 334.205834 -224.954676)
		(end 333.923132 -224.8789)
		(width 0.088646)
		(layer "In4.Cu")
		(net "M_B_CPU0_SB_DQS_DN<8>")
	)
	(arc
		(start 332.41869 -223.996758)
		(mid 332.40763 -223.986617)
		(end 332.396846 -223.976184)
		(width 0.088646)
		(layer "In4.Cu")
		(net "M_B_CPU0_SB_DQS_DN<8>")
	)
	(arc
		(start 332.513432 -224.065338)
		(mid 332.464282 -224.033505)
		(end 332.41869 -223.996758)
		(width 0.088646)
		(layer "In4.Cu")
		(net "M_B_CPU0_SB_DQS_DN<8>")
	)
	(arc
		(start 333.547974 -224.878646)
		(mid 333.265953 -224.954202)
		(end 332.98384 -224.8789)
		(width 0.088646)
		(layer "In4.Cu")
		(net "M_B_CPU0_SB_DQS_DN<8>")
	)
	(arc
		(start 334.866488 -224.880678)
		(mid 334.86318 -224.878783)
		(end 334.859884 -224.876868)
		(width 0.088646)
		(layer "In4.Cu")
		(net "M_B_CPU0_SB_DQS_DN<8>")
	)
	(arc
		(start 335.045812 -225.145854)
		(mid 335.043119 -225.129531)
		(end 335.039716 -225.113342)
		(width 0.088646)
		(layer "In4.Cu")
		(net "M_B_CPU0_SB_DQS_DN<8>")
	)
	(arc
		(start 334.859884 -224.876868)
		(mid 334.67397 -224.828507)
		(end 334.488536 -224.878646)
		(width 0.088646)
		(layer "In4.Cu")
		(net "M_B_CPU0_SB_DQS_DN<8>")
	)
	(arc
		(start 335.039716 -225.113342)
		(mid 334.976485 -224.979614)
		(end 334.866488 -224.880678)
		(width 0.088646)
		(layer "In4.Cu")
		(net "M_B_CPU0_SB_DQS_DN<8>")
	)
	(arc
		(start 332.977236 -224.875344)
		(mid 332.774649 -224.668993)
		(end 332.70063 -224.389442)
		(width 0.088646)
		(layer "In4.Cu")
		(net "M_B_CPU0_SB_DQS_DN<8>")
	)
	(arc
		(start 333.923132 -224.8789)
		(mid 333.735934 -224.828757)
		(end 333.548736 -224.8789)
		(width 0.088646)
		(layer "In4.Cu")
		(net "M_B_CPU0_SB_DQS_DN<8>")
	)
	(arc
		(start 332.70063 -224.389442)
		(mid 332.650466 -224.202304)
		(end 332.513432 -224.065338)
		(width 0.088646)
		(layer "In4.Cu")
		(net "M_B_CPU0_SB_DQS_DN<8>")
	)
	(segment
		(start 291.561774 -208.95564)
		(end 291.088572 -208.95564)
		(width 0.20066)
		(layer "F.Cu")
		(net "M_B_CPU0_SB_DQS_DN<7>")
	)
	(segment
		(start 291.088572 -208.95564)
		(end 290.82746 -209.216752)
		(width 0.20066)
		(layer "F.Cu")
		(net "M_B_CPU0_SB_DQS_DN<7>")
	)
	(segment
		(start 337.965034 -228.180646)
		(end 337.965034 -227.64496)
		(width 0.20066)
		(layer "F.Cu")
		(net "M_B_CPU0_SB_DQS_DN<7>")
	)
	(segment
		(start 295.142666 -208.79181)
		(end 295.000426 -208.79181)
		(width 0.20066)
		(layer "F.Cu")
		(net "M_B_CPU0_SB_DQS_DN<7>")
	)
	(segment
		(start 292.683184 -208.79181)
		(end 292.67531 -208.799684)
		(width 0.101854)
		(layer "F.Cu")
		(net "M_B_CPU0_SB_DQS_DN<7>")
	)
	(segment
		(start 297.409108 -209.216752)
		(end 297.147996 -208.95564)
		(width 0.20066)
		(layer "F.Cu")
		(net "M_B_CPU0_SB_DQS_DN<7>")
	)
	(segment
		(start 295.403778 -208.530698)
		(end 295.142666 -208.79181)
		(width 0.20066)
		(layer "F.Cu")
		(net "M_B_CPU0_SB_DQS_DN<7>")
	)
	(segment
		(start 296.444416 -208.95564)
		(end 295.8084 -208.530698)
		(width 0.20066)
		(layer "F.Cu")
		(net "M_B_CPU0_SB_DQS_DN<7>")
	)
	(segment
		(start 295.8084 -208.530698)
		(end 295.403778 -208.530698)
		(width 0.20066)
		(layer "F.Cu")
		(net "M_B_CPU0_SB_DQS_DN<7>")
	)
	(segment
		(start 295.000426 -208.79181)
		(end 292.92296 -208.79181)
		(width 0.1016)
		(layer "F.Cu")
		(net "M_B_CPU0_SB_DQS_DN<7>")
	)
	(segment
		(start 292.490398 -208.799684)
		(end 292.223952 -208.533238)
		(width 0.20066)
		(layer "F.Cu")
		(net "M_B_CPU0_SB_DQS_DN<7>")
	)
	(segment
		(start 337.96478 -228.1809)
		(end 337.965034 -228.180646)
		(width 0.20066)
		(layer "F.Cu")
		(net "M_B_CPU0_SB_DQS_DN<7>")
	)
	(segment
		(start 292.92296 -208.79181)
		(end 292.683184 -208.79181)
		(width 0.101854)
		(layer "F.Cu")
		(net "M_B_CPU0_SB_DQS_DN<7>")
	)
	(segment
		(start 297.147996 -208.95564)
		(end 296.444416 -208.95564)
		(width 0.20066)
		(layer "F.Cu")
		(net "M_B_CPU0_SB_DQS_DN<7>")
	)
	(segment
		(start 297.899582 -209.216752)
		(end 297.409108 -209.216752)
		(width 0.20066)
		(layer "F.Cu")
		(net "M_B_CPU0_SB_DQS_DN<7>")
	)
	(segment
		(start 290.82746 -209.216752)
		(end 290.355782 -209.216752)
		(width 0.20066)
		(layer "F.Cu")
		(net "M_B_CPU0_SB_DQS_DN<7>")
	)
	(segment
		(start 291.984176 -208.533238)
		(end 291.561774 -208.95564)
		(width 0.20066)
		(layer "F.Cu")
		(net "M_B_CPU0_SB_DQS_DN<7>")
	)
	(segment
		(start 292.223952 -208.533238)
		(end 291.984176 -208.533238)
		(width 0.20066)
		(layer "F.Cu")
		(net "M_B_CPU0_SB_DQS_DN<7>")
	)
	(segment
		(start 292.67531 -208.799684)
		(end 292.490398 -208.799684)
		(width 0.20066)
		(layer "F.Cu")
		(net "M_B_CPU0_SB_DQS_DN<7>")
	)
	(segment
		(start 299.004482 -209.216752)
		(end 297.899582 -209.216752)
		(width 0.20066)
		(layer "F.Cu")
		(net "M_B_CPU0_SB_DQS_DN<7>")
	)
	(segment
		(start 312.573162 -207.65389)
		(end 312.378344 -207.848708)
		(width 0.18288)
		(layer "In2.Cu")
		(net "M_B_CPU0_SB_DQS_DN<7>")
	)
	(segment
		(start 313.59094 -207.838548)
		(end 313.406282 -207.65389)
		(width 0.18288)
		(layer "In2.Cu")
		(net "M_B_CPU0_SB_DQS_DN<7>")
	)
	(segment
		(start 308.161436 -207.128364)
		(end 308.133242 -207.156558)
		(width 0.16002)
		(layer "In2.Cu")
		(net "M_B_CPU0_SB_DQS_DN<7>")
	)
	(segment
		(start 317.949326 -208.327752)
		(end 317.400686 -208.327752)
		(width 0.18288)
		(layer "In2.Cu")
		(net "M_B_CPU0_SB_DQS_DN<7>")
	)
	(segment
		(start 304.69205 -207.996282)
		(end 304.675794 -207.996282)
		(width 0.16002)
		(layer "In2.Cu")
		(net "M_B_CPU0_SB_DQS_DN<7>")
	)
	(segment
		(start 333.64043 -222.769176)
		(end 333.64043 -222.761556)
		(width 0.088646)
		(layer "In2.Cu")
		(net "M_B_CPU0_SB_DQS_DN<7>")
	)
	(segment
		(start 302.407828 -208.019904)
		(end 302.39208 -208.019904)
		(width 0.16002)
		(layer "In2.Cu")
		(net "M_B_CPU0_SB_DQS_DN<7>")
	)
	(segment
		(start 333.293974 -222.269812)
		(end 332.627224 -222.269812)
		(width 0.088646)
		(layer "In2.Cu")
		(net "M_B_CPU0_SB_DQS_DN<7>")
	)
	(segment
		(start 300.498002 -208.916524)
		(end 300.498002 -208.93278)
		(width 0.16002)
		(layer "In2.Cu")
		(net "M_B_CPU0_SB_DQS_DN<7>")
	)
	(segment
		(start 315.256926 -208.327752)
		(end 314.080144 -208.327752)
		(width 0.18288)
		(layer "In2.Cu")
		(net "M_B_CPU0_SB_DQS_DN<7>")
	)
	(segment
		(start 304.447956 -208.240376)
		(end 304.297842 -208.39049)
		(width 0.18288)
		(layer "In2.Cu")
		(net "M_B_CPU0_SB_DQS_DN<7>")
	)
	(segment
		(start 329.395074 -219.949522)
		(end 329.006962 -219.56141)
		(width 0.18288)
		(layer "In2.Cu")
		(net "M_B_CPU0_SB_DQS_DN<7>")
	)
	(segment
		(start 302.191928 -208.220056)
		(end 302.191928 -208.235804)
		(width 0.16002)
		(layer "In2.Cu")
		(net "M_B_CPU0_SB_DQS_DN<7>")
	)
	(segment
		(start 300.257972 -209.17281)
		(end 299.711364 -209.17281)
		(width 0.18288)
		(layer "In2.Cu")
		(net "M_B_CPU0_SB_DQS_DN<7>")
	)
	(segment
		(start 335.802732 -226.506786)
		(end 335.801208 -226.506024)
		(width 0.088646)
		(layer "In2.Cu")
		(net "M_B_CPU0_SB_DQS_DN<7>")
	)
	(segment
		(start 338.153756 -227.321364)
		(end 338.152232 -227.320602)
		(width 0.088646)
		(layer "In2.Cu")
		(net "M_B_CPU0_SB_DQS_DN<7>")
	)
	(segment
		(start 309.612792 -207.128364)
		(end 309.520336 -207.035908)
		(width 0.18288)
		(layer "In2.Cu")
		(net "M_B_CPU0_SB_DQS_DN<7>")
	)
	(segment
		(start 307.09362 -207.81518)
		(end 306.798472 -208.110328)
		(width 0.18288)
		(layer "In2.Cu")
		(net "M_B_CPU0_SB_DQS_DN<7>")
	)
	(segment
		(start 335.801208 -226.506024)
		(end 335.799938 -226.505262)
		(width 0.088646)
		(layer "In2.Cu")
		(net "M_B_CPU0_SB_DQS_DN<7>")
	)
	(segment
		(start 309.657242 -207.156558)
		(end 309.640986 -207.156558)
		(width 0.16002)
		(layer "In2.Cu")
		(net "M_B_CPU0_SB_DQS_DN<7>")
	)
	(segment
		(start 312.378344 -207.848708)
		(end 312.35015 -207.876902)
		(width 0.16002)
		(layer "In2.Cu")
		(net "M_B_CPU0_SB_DQS_DN<7>")
	)
	(segment
		(start 304.675794 -207.996282)
		(end 304.47615 -208.195926)
		(width 0.16002)
		(layer "In2.Cu")
		(net "M_B_CPU0_SB_DQS_DN<7>")
	)
	(segment
		(start 302.39208 -208.019904)
		(end 302.191928 -208.220056)
		(width 0.16002)
		(layer "In2.Cu")
		(net "M_B_CPU0_SB_DQS_DN<7>")
	)
	(segment
		(start 304.945542 -207.74279)
		(end 304.720244 -207.968088)
		(width 0.18288)
		(layer "In2.Cu")
		(net "M_B_CPU0_SB_DQS_DN<7>")
	)
	(segment
		(start 313.406282 -207.65389)
		(end 312.573162 -207.65389)
		(width 0.18288)
		(layer "In2.Cu")
		(net "M_B_CPU0_SB_DQS_DN<7>")
	)
	(segment
		(start 316.727586 -208.452212)
		(end 316.603126 -208.327752)
		(width 0.18288)
		(layer "In2.Cu")
		(net "M_B_CPU0_SB_DQS_DN<7>")
	)
	(segment
		(start 304.47615 -208.195926)
		(end 304.47615 -208.212182)
		(width 0.16002)
		(layer "In2.Cu")
		(net "M_B_CPU0_SB_DQS_DN<7>")
	)
	(segment
		(start 313.619134 -207.866742)
		(end 313.59094 -207.838548)
		(width 0.16002)
		(layer "In2.Cu")
		(net "M_B_CPU0_SB_DQS_DN<7>")
	)
	(segment
		(start 316.054486 -208.327752)
		(end 315.930026 -208.452212)
		(width 0.18288)
		(layer "In2.Cu")
		(net "M_B_CPU0_SB_DQS_DN<7>")
	)
	(segment
		(start 305.53025 -207.74279)
		(end 304.945542 -207.74279)
		(width 0.18288)
		(layer "In2.Cu")
		(net "M_B_CPU0_SB_DQS_DN<7>")
	)
	(segment
		(start 302.494442 -207.93329)
		(end 302.436022 -207.99171)
		(width 0.18288)
		(layer "In2.Cu")
		(net "M_B_CPU0_SB_DQS_DN<7>")
	)
	(segment
		(start 299.711364 -209.17281)
		(end 299.486066 -208.947512)
		(width 0.18288)
		(layer "In2.Cu")
		(net "M_B_CPU0_SB_DQS_DN<7>")
	)
	(segment
		(start 312.35015 -207.876902)
		(end 312.333894 -207.876902)
		(width 0.16002)
		(layer "In2.Cu")
		(net "M_B_CPU0_SB_DQS_DN<7>")
	)
	(segment
		(start 309.856886 -207.356202)
		(end 309.657242 -207.156558)
		(width 0.16002)
		(layer "In2.Cu")
		(net "M_B_CPU0_SB_DQS_DN<7>")
	)
	(segment
		(start 334.401922 -224.070164)
		(end 334.393032 -224.065084)
		(width 0.088646)
		(layer "In2.Cu")
		(net "M_B_CPU0_SB_DQS_DN<7>")
	)
	(segment
		(start 307.917342 -207.356202)
		(end 307.917342 -207.372458)
		(width 0.16002)
		(layer "In2.Cu")
		(net "M_B_CPU0_SB_DQS_DN<7>")
	)
	(segment
		(start 307.889148 -207.400652)
		(end 307.47462 -207.81518)
		(width 0.18288)
		(layer "In2.Cu")
		(net "M_B_CPU0_SB_DQS_DN<7>")
	)
	(segment
		(start 329.571096 -219.949522)
		(end 329.395074 -219.949522)
		(width 0.18288)
		(layer "In2.Cu")
		(net "M_B_CPU0_SB_DQS_DN<7>")
	)
	(segment
		(start 305.606958 -207.819498)
		(end 305.53025 -207.74279)
		(width 0.18288)
		(layer "In2.Cu")
		(net "M_B_CPU0_SB_DQS_DN<7>")
	)
	(segment
		(start 313.63539 -207.866742)
		(end 313.619134 -207.866742)
		(width 0.16002)
		(layer "In2.Cu")
		(net "M_B_CPU0_SB_DQS_DN<7>")
	)
	(segment
		(start 304.47615 -208.212182)
		(end 304.447956 -208.240376)
		(width 0.16002)
		(layer "In2.Cu")
		(net "M_B_CPU0_SB_DQS_DN<7>")
	)
	(segment
		(start 301.889922 -208.53781)
		(end 300.892972 -208.53781)
		(width 0.18288)
		(layer "In2.Cu")
		(net "M_B_CPU0_SB_DQS_DN<7>")
	)
	(segment
		(start 333.923894 -223.251776)
		(end 333.923132 -223.251268)
		(width 0.088646)
		(layer "In2.Cu")
		(net "M_B_CPU0_SB_DQS_DN<7>")
	)
	(segment
		(start 316.603126 -208.327752)
		(end 316.054486 -208.327752)
		(width 0.18288)
		(layer "In2.Cu")
		(net "M_B_CPU0_SB_DQS_DN<7>")
	)
	(segment
		(start 314.080144 -208.327752)
		(end 313.863228 -208.110836)
		(width 0.18288)
		(layer "In2.Cu")
		(net "M_B_CPU0_SB_DQS_DN<7>")
	)
	(segment
		(start 332.56728 -222.329756)
		(end 331.95133 -222.329756)
		(width 0.18288)
		(layer "In2.Cu")
		(net "M_B_CPU0_SB_DQS_DN<7>")
	)
	(segment
		(start 317.400686 -208.327752)
		(end 317.276226 -208.452212)
		(width 0.18288)
		(layer "In2.Cu")
		(net "M_B_CPU0_SB_DQS_DN<7>")
	)
	(segment
		(start 313.835034 -208.082642)
		(end 313.835034 -208.066386)
		(width 0.16002)
		(layer "In2.Cu")
		(net "M_B_CPU0_SB_DQS_DN<7>")
	)
	(segment
		(start 302.163734 -208.263998)
		(end 301.889922 -208.53781)
		(width 0.18288)
		(layer "In2.Cu")
		(net "M_B_CPU0_SB_DQS_DN<7>")
	)
	(segment
		(start 334.110584 -223.585532)
		(end 334.110584 -223.575626)
		(width 0.088646)
		(layer "In2.Cu")
		(net "M_B_CPU0_SB_DQS_DN<7>")
	)
	(segment
		(start 299.273722 -208.947512)
		(end 299.004482 -209.216752)
		(width 0.18288)
		(layer "In2.Cu")
		(net "M_B_CPU0_SB_DQS_DN<7>")
	)
	(segment
		(start 311.889902 -208.33715)
		(end 310.821578 -208.33715)
		(width 0.18288)
		(layer "In2.Cu")
		(net "M_B_CPU0_SB_DQS_DN<7>")
	)
	(segment
		(start 312.13425 -208.092802)
		(end 312.106056 -208.120996)
		(width 0.16002)
		(layer "In2.Cu")
		(net "M_B_CPU0_SB_DQS_DN<7>")
	)
	(segment
		(start 333.473806 -222.449644)
		(end 333.293974 -222.269812)
		(width 0.088646)
		(layer "In2.Cu")
		(net "M_B_CPU0_SB_DQS_DN<7>")
	)
	(segment
		(start 335.795112 -226.502214)
		(end 335.79054 -226.499674)
		(width 0.088646)
		(layer "In2.Cu")
		(net "M_B_CPU0_SB_DQS_DN<7>")
	)
	(segment
		(start 335.802732 -225.527616)
		(end 335.803494 -225.527108)
		(width 0.088646)
		(layer "In2.Cu")
		(net "M_B_CPU0_SB_DQS_DN<7>")
	)
	(segment
		(start 337.965034 -227.64496)
		(end 338.277962 -227.64496)
		(width 0.088646)
		(layer "In2.Cu")
		(net "M_B_CPU0_SB_DQS_DN<7>")
	)
	(segment
		(start 300.892972 -208.53781)
		(end 300.742096 -208.688686)
		(width 0.18288)
		(layer "In2.Cu")
		(net "M_B_CPU0_SB_DQS_DN<7>")
	)
	(segment
		(start 312.13425 -208.076546)
		(end 312.13425 -208.092802)
		(width 0.16002)
		(layer "In2.Cu")
		(net "M_B_CPU0_SB_DQS_DN<7>")
	)
	(segment
		(start 300.713902 -208.71688)
		(end 300.697646 -208.71688)
		(width 0.16002)
		(layer "In2.Cu")
		(net "M_B_CPU0_SB_DQS_DN<7>")
	)
	(segment
		(start 309.640986 -207.156558)
		(end 309.612792 -207.128364)
		(width 0.16002)
		(layer "In2.Cu")
		(net "M_B_CPU0_SB_DQS_DN<7>")
	)
	(segment
		(start 309.88508 -207.400652)
		(end 309.856886 -207.372458)
		(width 0.16002)
		(layer "In2.Cu")
		(net "M_B_CPU0_SB_DQS_DN<7>")
	)
	(segment
		(start 312.333894 -207.876902)
		(end 312.13425 -208.076546)
		(width 0.16002)
		(layer "In2.Cu")
		(net "M_B_CPU0_SB_DQS_DN<7>")
	)
	(segment
		(start 337.227164 -227.329238)
		(end 337.212432 -227.320602)
		(width 0.088646)
		(layer "In2.Cu")
		(net "M_B_CPU0_SB_DQS_DN<7>")
	)
	(segment
		(start 309.520336 -207.035908)
		(end 308.253892 -207.035908)
		(width 0.18288)
		(layer "In2.Cu")
		(net "M_B_CPU0_SB_DQS_DN<7>")
	)
	(segment
		(start 307.917342 -207.372458)
		(end 307.889148 -207.400652)
		(width 0.16002)
		(layer "In2.Cu")
		(net "M_B_CPU0_SB_DQS_DN<7>")
	)
	(segment
		(start 309.856886 -207.372458)
		(end 309.856886 -207.356202)
		(width 0.16002)
		(layer "In2.Cu")
		(net "M_B_CPU0_SB_DQS_DN<7>")
	)
	(segment
		(start 306.366418 -208.110328)
		(end 306.075588 -207.819498)
		(width 0.18288)
		(layer "In2.Cu")
		(net "M_B_CPU0_SB_DQS_DN<7>")
	)
	(segment
		(start 331.95133 -222.329756)
		(end 329.571096 -219.949522)
		(width 0.18288)
		(layer "In2.Cu")
		(net "M_B_CPU0_SB_DQS_DN<7>")
	)
	(segment
		(start 308.116986 -207.156558)
		(end 307.917342 -207.356202)
		(width 0.16002)
		(layer "In2.Cu")
		(net "M_B_CPU0_SB_DQS_DN<7>")
	)
	(segment
		(start 317.276226 -208.452212)
		(end 316.727586 -208.452212)
		(width 0.18288)
		(layer "In2.Cu")
		(net "M_B_CPU0_SB_DQS_DN<7>")
	)
	(segment
		(start 338.277962 -227.64496)
		(end 338.335112 -227.58781)
		(width 0.088646)
		(layer "In2.Cu")
		(net "M_B_CPU0_SB_DQS_DN<7>")
	)
	(segment
		(start 333.64043 -222.761556)
		(end 333.640938 -222.761556)
		(width 0.088646)
		(layer "In2.Cu")
		(net "M_B_CPU0_SB_DQS_DN<7>")
	)
	(segment
		(start 313.835034 -208.066386)
		(end 313.63539 -207.866742)
		(width 0.16002)
		(layer "In2.Cu")
		(net "M_B_CPU0_SB_DQS_DN<7>")
	)
	(segment
		(start 335.799938 -226.505262)
		(end 335.797144 -226.503484)
		(width 0.088646)
		(layer "In2.Cu")
		(net "M_B_CPU0_SB_DQS_DN<7>")
	)
	(segment
		(start 308.133242 -207.156558)
		(end 308.116986 -207.156558)
		(width 0.16002)
		(layer "In2.Cu")
		(net "M_B_CPU0_SB_DQS_DN<7>")
	)
	(segment
		(start 335.98993 -226.831144)
		(end 335.98993 -226.822508)
		(width 0.088646)
		(layer "In2.Cu")
		(net "M_B_CPU0_SB_DQS_DN<7>")
	)
	(segment
		(start 302.95977 -207.93329)
		(end 302.494442 -207.93329)
		(width 0.18288)
		(layer "In2.Cu")
		(net "M_B_CPU0_SB_DQS_DN<7>")
	)
	(segment
		(start 308.253892 -207.035908)
		(end 308.161436 -207.128364)
		(width 0.18288)
		(layer "In2.Cu")
		(net "M_B_CPU0_SB_DQS_DN<7>")
	)
	(segment
		(start 300.498002 -208.93278)
		(end 300.469808 -208.960974)
		(width 0.16002)
		(layer "In2.Cu")
		(net "M_B_CPU0_SB_DQS_DN<7>")
	)
	(segment
		(start 302.436022 -207.99171)
		(end 302.407828 -208.019904)
		(width 0.16002)
		(layer "In2.Cu")
		(net "M_B_CPU0_SB_DQS_DN<7>")
	)
	(segment
		(start 307.47462 -207.81518)
		(end 307.09362 -207.81518)
		(width 0.18288)
		(layer "In2.Cu")
		(net "M_B_CPU0_SB_DQS_DN<7>")
	)
	(segment
		(start 335.803494 -225.527108)
		(end 335.811622 -225.522536)
		(width 0.088646)
		(layer "In2.Cu")
		(net "M_B_CPU0_SB_DQS_DN<7>")
	)
	(segment
		(start 335.797144 -226.503484)
		(end 335.795112 -226.502214)
		(width 0.088646)
		(layer "In2.Cu")
		(net "M_B_CPU0_SB_DQS_DN<7>")
	)
	(segment
		(start 333.932022 -223.256348)
		(end 333.923894 -223.251776)
		(width 0.088646)
		(layer "In2.Cu")
		(net "M_B_CPU0_SB_DQS_DN<7>")
	)
	(segment
		(start 299.486066 -208.947512)
		(end 299.273722 -208.947512)
		(width 0.18288)
		(layer "In2.Cu")
		(net "M_B_CPU0_SB_DQS_DN<7>")
	)
	(segment
		(start 315.381386 -208.452212)
		(end 315.256926 -208.327752)
		(width 0.18288)
		(layer "In2.Cu")
		(net "M_B_CPU0_SB_DQS_DN<7>")
	)
	(segment
		(start 329.006962 -219.385388)
		(end 317.949326 -208.327752)
		(width 0.18288)
		(layer "In2.Cu")
		(net "M_B_CPU0_SB_DQS_DN<7>")
	)
	(segment
		(start 302.191928 -208.235804)
		(end 302.163734 -208.263998)
		(width 0.16002)
		(layer "In2.Cu")
		(net "M_B_CPU0_SB_DQS_DN<7>")
	)
	(segment
		(start 304.720244 -207.968088)
		(end 304.69205 -207.996282)
		(width 0.16002)
		(layer "In2.Cu")
		(net "M_B_CPU0_SB_DQS_DN<7>")
	)
	(segment
		(start 334.580484 -224.399348)
		(end 334.580484 -224.389442)
		(width 0.088646)
		(layer "In2.Cu")
		(net "M_B_CPU0_SB_DQS_DN<7>")
	)
	(segment
		(start 300.697646 -208.71688)
		(end 300.498002 -208.916524)
		(width 0.16002)
		(layer "In2.Cu")
		(net "M_B_CPU0_SB_DQS_DN<7>")
	)
	(segment
		(start 300.742096 -208.688686)
		(end 300.713902 -208.71688)
		(width 0.16002)
		(layer "In2.Cu")
		(net "M_B_CPU0_SB_DQS_DN<7>")
	)
	(segment
		(start 329.006962 -219.56141)
		(end 329.006962 -219.385388)
		(width 0.18288)
		(layer "In2.Cu")
		(net "M_B_CPU0_SB_DQS_DN<7>")
	)
	(segment
		(start 312.106056 -208.120996)
		(end 311.889902 -208.33715)
		(width 0.18288)
		(layer "In2.Cu")
		(net "M_B_CPU0_SB_DQS_DN<7>")
	)
	(segment
		(start 313.863228 -208.110836)
		(end 313.835034 -208.082642)
		(width 0.16002)
		(layer "In2.Cu")
		(net "M_B_CPU0_SB_DQS_DN<7>")
	)
	(segment
		(start 332.627224 -222.269812)
		(end 332.56728 -222.329756)
		(width 0.088646)
		(layer "In2.Cu")
		(net "M_B_CPU0_SB_DQS_DN<7>")
	)
	(segment
		(start 303.41697 -208.39049)
		(end 302.95977 -207.93329)
		(width 0.18288)
		(layer "In2.Cu")
		(net "M_B_CPU0_SB_DQS_DN<7>")
	)
	(segment
		(start 304.297842 -208.39049)
		(end 303.41697 -208.39049)
		(width 0.18288)
		(layer "In2.Cu")
		(net "M_B_CPU0_SB_DQS_DN<7>")
	)
	(segment
		(start 300.469808 -208.960974)
		(end 300.257972 -209.17281)
		(width 0.18288)
		(layer "In2.Cu")
		(net "M_B_CPU0_SB_DQS_DN<7>")
	)
	(segment
		(start 306.075588 -207.819498)
		(end 305.606958 -207.819498)
		(width 0.18288)
		(layer "In2.Cu")
		(net "M_B_CPU0_SB_DQS_DN<7>")
	)
	(segment
		(start 310.821578 -208.33715)
		(end 309.88508 -207.400652)
		(width 0.18288)
		(layer "In2.Cu")
		(net "M_B_CPU0_SB_DQS_DN<7>")
	)
	(segment
		(start 315.930026 -208.452212)
		(end 315.381386 -208.452212)
		(width 0.18288)
		(layer "In2.Cu")
		(net "M_B_CPU0_SB_DQS_DN<7>")
	)
	(segment
		(start 306.798472 -208.110328)
		(end 306.366418 -208.110328)
		(width 0.18288)
		(layer "In2.Cu")
		(net "M_B_CPU0_SB_DQS_DN<7>")
	)
	(arc
		(start 335.98993 -226.822508)
		(mid 335.93766 -226.640143)
		(end 335.802732 -226.506786)
		(width 0.088646)
		(layer "In2.Cu")
		(net "M_B_CPU0_SB_DQS_DN<7>")
	)
	(arc
		(start 333.640938 -222.761556)
		(mid 333.596524 -222.584619)
		(end 333.473806 -222.449644)
		(width 0.088646)
		(layer "In2.Cu")
		(net "M_B_CPU0_SB_DQS_DN<7>")
	)
	(arc
		(start 338.152232 -227.320602)
		(mid 337.965034 -227.270459)
		(end 337.777836 -227.320602)
		(width 0.088646)
		(layer "In2.Cu")
		(net "M_B_CPU0_SB_DQS_DN<7>")
	)
	(arc
		(start 335.428336 -224.8789)
		(mid 334.86736 -224.881431)
		(end 334.580484 -224.399348)
		(width 0.088646)
		(layer "In2.Cu")
		(net "M_B_CPU0_SB_DQS_DN<7>")
	)
	(arc
		(start 338.335112 -227.58781)
		(mid 338.274538 -227.4341)
		(end 338.153756 -227.321364)
		(width 0.088646)
		(layer "In2.Cu")
		(net "M_B_CPU0_SB_DQS_DN<7>")
	)
	(arc
		(start 334.393032 -224.065084)
		(mid 334.188697 -223.862479)
		(end 334.110584 -223.585532)
		(width 0.088646)
		(layer "In2.Cu")
		(net "M_B_CPU0_SB_DQS_DN<7>")
	)
	(arc
		(start 336.838036 -227.320602)
		(mid 336.272537 -227.320841)
		(end 335.98993 -226.831144)
		(width 0.088646)
		(layer "In2.Cu")
		(net "M_B_CPU0_SB_DQS_DN<7>")
	)
	(arc
		(start 334.110584 -223.575626)
		(mid 334.062905 -223.392726)
		(end 333.932022 -223.256348)
		(width 0.088646)
		(layer "In2.Cu")
		(net "M_B_CPU0_SB_DQS_DN<7>")
	)
	(arc
		(start 333.923132 -223.251268)
		(mid 333.71806 -223.047589)
		(end 333.64043 -222.769176)
		(width 0.088646)
		(layer "In2.Cu")
		(net "M_B_CPU0_SB_DQS_DN<7>")
	)
	(arc
		(start 337.212432 -227.320602)
		(mid 337.025234 -227.270459)
		(end 336.838036 -227.320602)
		(width 0.088646)
		(layer "In2.Cu")
		(net "M_B_CPU0_SB_DQS_DN<7>")
	)
	(arc
		(start 337.777836 -227.320602)
		(mid 337.503637 -227.396437)
		(end 337.227164 -227.329238)
		(width 0.088646)
		(layer "In2.Cu")
		(net "M_B_CPU0_SB_DQS_DN<7>")
	)
	(arc
		(start 334.580484 -224.389442)
		(mid 334.532805 -224.206542)
		(end 334.401922 -224.070164)
		(width 0.088646)
		(layer "In2.Cu")
		(net "M_B_CPU0_SB_DQS_DN<7>")
	)
	(arc
		(start 335.79054 -226.499674)
		(mid 335.520008 -226.010207)
		(end 335.802732 -225.527616)
		(width 0.088646)
		(layer "In2.Cu")
		(net "M_B_CPU0_SB_DQS_DN<7>")
	)
	(arc
		(start 335.811622 -225.522536)
		(mid 335.937462 -225.011551)
		(end 335.428336 -224.8789)
		(width 0.088646)
		(layer "In2.Cu")
		(net "M_B_CPU0_SB_DQS_DN<7>")
	)
	(segment
		(start 337.96478 -233.064304)
		(end 337.965034 -233.06405)
		(width 0.20066)
		(layer "F.Cu")
		(net "M_B_CPU0_SB_DQS_DN<6>")
	)
	(segment
		(start 297.899582 -218.566746)
		(end 297.409108 -218.566746)
		(width 0.20066)
		(layer "F.Cu")
		(net "M_B_CPU0_SB_DQS_DN<6>")
	)
	(segment
		(start 291.984176 -217.883232)
		(end 291.561774 -218.305634)
		(width 0.20066)
		(layer "F.Cu")
		(net "M_B_CPU0_SB_DQS_DN<6>")
	)
	(segment
		(start 292.490398 -218.149678)
		(end 292.223952 -217.883232)
		(width 0.20066)
		(layer "F.Cu")
		(net "M_B_CPU0_SB_DQS_DN<6>")
	)
	(segment
		(start 290.82746 -218.566746)
		(end 290.355782 -218.566746)
		(width 0.20066)
		(layer "F.Cu")
		(net "M_B_CPU0_SB_DQS_DN<6>")
	)
	(segment
		(start 295.000426 -218.141804)
		(end 292.92296 -218.141804)
		(width 0.1016)
		(layer "F.Cu")
		(net "M_B_CPU0_SB_DQS_DN<6>")
	)
	(segment
		(start 292.67531 -218.149678)
		(end 292.490398 -218.149678)
		(width 0.20066)
		(layer "F.Cu")
		(net "M_B_CPU0_SB_DQS_DN<6>")
	)
	(segment
		(start 295.8084 -217.880692)
		(end 295.403778 -217.880692)
		(width 0.20066)
		(layer "F.Cu")
		(net "M_B_CPU0_SB_DQS_DN<6>")
	)
	(segment
		(start 295.403778 -217.880692)
		(end 295.142666 -218.141804)
		(width 0.20066)
		(layer "F.Cu")
		(net "M_B_CPU0_SB_DQS_DN<6>")
	)
	(segment
		(start 292.92296 -218.141804)
		(end 292.683184 -218.141804)
		(width 0.101854)
		(layer "F.Cu")
		(net "M_B_CPU0_SB_DQS_DN<6>")
	)
	(segment
		(start 291.088572 -218.305634)
		(end 290.82746 -218.566746)
		(width 0.20066)
		(layer "F.Cu")
		(net "M_B_CPU0_SB_DQS_DN<6>")
	)
	(segment
		(start 337.965034 -233.06405)
		(end 337.965034 -232.528364)
		(width 0.20066)
		(layer "F.Cu")
		(net "M_B_CPU0_SB_DQS_DN<6>")
	)
	(segment
		(start 295.142666 -218.141804)
		(end 295.000426 -218.141804)
		(width 0.20066)
		(layer "F.Cu")
		(net "M_B_CPU0_SB_DQS_DN<6>")
	)
	(segment
		(start 299.004482 -218.566746)
		(end 297.899582 -218.566746)
		(width 0.20066)
		(layer "F.Cu")
		(net "M_B_CPU0_SB_DQS_DN<6>")
	)
	(segment
		(start 297.147996 -218.305634)
		(end 296.444416 -218.305634)
		(width 0.20066)
		(layer "F.Cu")
		(net "M_B_CPU0_SB_DQS_DN<6>")
	)
	(segment
		(start 296.444416 -218.305634)
		(end 295.8084 -217.880692)
		(width 0.20066)
		(layer "F.Cu")
		(net "M_B_CPU0_SB_DQS_DN<6>")
	)
	(segment
		(start 291.561774 -218.305634)
		(end 291.088572 -218.305634)
		(width 0.20066)
		(layer "F.Cu")
		(net "M_B_CPU0_SB_DQS_DN<6>")
	)
	(segment
		(start 292.223952 -217.883232)
		(end 291.984176 -217.883232)
		(width 0.20066)
		(layer "F.Cu")
		(net "M_B_CPU0_SB_DQS_DN<6>")
	)
	(segment
		(start 292.683184 -218.141804)
		(end 292.67531 -218.149678)
		(width 0.101854)
		(layer "F.Cu")
		(net "M_B_CPU0_SB_DQS_DN<6>")
	)
	(segment
		(start 297.409108 -218.566746)
		(end 297.147996 -218.305634)
		(width 0.20066)
		(layer "F.Cu")
		(net "M_B_CPU0_SB_DQS_DN<6>")
	)
	(segment
		(start 300.690026 -218.09075)
		(end 300.640496 -218.14028)
		(width 0.18288)
		(layer "In2.Cu")
		(net "M_B_CPU0_SB_DQS_DN<6>")
	)
	(segment
		(start 304.470308 -219.14612)
		(end 304.470308 -219.130372)
		(width 0.16002)
		(layer "In2.Cu")
		(net "M_B_CPU0_SB_DQS_DN<6>")
	)
	(segment
		(start 331.649578 -231.863392)
		(end 331.564742 -231.863392)
		(width 0.088646)
		(layer "In2.Cu")
		(net "M_B_CPU0_SB_DQS_DN<6>")
	)
	(segment
		(start 310.02224 -218.577668)
		(end 309.8673 -218.422728)
		(width 0.18288)
		(layer "In2.Cu")
		(net "M_B_CPU0_SB_DQS_DN<6>")
	)
	(segment
		(start 302.097186 -218.206574)
		(end 302.068992 -218.17838)
		(width 0.16002)
		(layer "In2.Cu")
		(net "M_B_CPU0_SB_DQS_DN<6>")
	)
	(segment
		(start 306.616608 -218.93022)
		(end 306.416456 -219.130372)
		(width 0.16002)
		(layer "In2.Cu")
		(net "M_B_CPU0_SB_DQS_DN<6>")
	)
	(segment
		(start 311.231534 -217.902536)
		(end 310.556402 -218.577668)
		(width 0.18288)
		(layer "In2.Cu")
		(net "M_B_CPU0_SB_DQS_DN<6>")
	)
	(segment
		(start 309.8673 -218.422728)
		(end 309.839106 -218.394534)
		(width 0.16002)
		(layer "In2.Cu")
		(net "M_B_CPU0_SB_DQS_DN<6>")
	)
	(segment
		(start 312.01741 -217.572336)
		(end 311.989216 -217.60053)
		(width 0.16002)
		(layer "In2.Cu")
		(net "M_B_CPU0_SB_DQS_DN<6>")
	)
	(segment
		(start 304.254408 -218.93022)
		(end 304.226214 -218.902026)
		(width 0.16002)
		(layer "In2.Cu")
		(net "M_B_CPU0_SB_DQS_DN<6>")
	)
	(segment
		(start 337.965034 -232.528364)
		(end 338.277708 -232.528364)
		(width 0.088646)
		(layer "In2.Cu")
		(net "M_B_CPU0_SB_DQS_DN<6>")
	)
	(segment
		(start 325.174864 -225.466148)
		(end 325.174864 -225.290126)
		(width 0.18288)
		(layer "In2.Cu")
		(net "M_B_CPU0_SB_DQS_DN<6>")
	)
	(segment
		(start 332.32598 -232.153206)
		(end 331.938884 -232.153206)
		(width 0.088646)
		(layer "In2.Cu")
		(net "M_B_CPU0_SB_DQS_DN<6>")
	)
	(segment
		(start 299.280326 -218.290902)
		(end 299.004482 -218.566746)
		(width 0.18288)
		(layer "In2.Cu")
		(net "M_B_CPU0_SB_DQS_DN<6>")
	)
	(segment
		(start 309.549038 -218.104466)
		(end 308.23535 -218.104466)
		(width 0.18288)
		(layer "In2.Cu")
		(net "M_B_CPU0_SB_DQS_DN<6>")
	)
	(segment
		(start 307.634386 -218.70543)
		(end 306.857146 -218.70543)
		(width 0.18288)
		(layer "In2.Cu")
		(net "M_B_CPU0_SB_DQS_DN<6>")
	)
	(segment
		(start 325.738998 -225.85426)
		(end 325.562976 -225.85426)
		(width 0.18288)
		(layer "In2.Cu")
		(net "M_B_CPU0_SB_DQS_DN<6>")
	)
	(segment
		(start 308.23535 -218.104466)
		(end 308.161436 -218.17838)
		(width 0.18288)
		(layer "In2.Cu")
		(net "M_B_CPU0_SB_DQS_DN<6>")
	)
	(segment
		(start 324.610984 -224.902268)
		(end 324.222872 -224.514156)
		(width 0.18288)
		(layer "In2.Cu")
		(net "M_B_CPU0_SB_DQS_DN<6>")
	)
	(segment
		(start 306.857146 -218.70543)
		(end 306.66055 -218.902026)
		(width 0.18288)
		(layer "In2.Cu")
		(net "M_B_CPU0_SB_DQS_DN<6>")
	)
	(segment
		(start 302.113442 -218.206574)
		(end 302.097186 -218.206574)
		(width 0.16002)
		(layer "In2.Cu")
		(net "M_B_CPU0_SB_DQS_DN<6>")
	)
	(segment
		(start 302.545242 -218.65463)
		(end 302.34128 -218.450668)
		(width 0.18288)
		(layer "In2.Cu")
		(net "M_B_CPU0_SB_DQS_DN<6>")
	)
	(segment
		(start 307.917342 -218.422474)
		(end 307.889148 -218.450668)
		(width 0.16002)
		(layer "In2.Cu")
		(net "M_B_CPU0_SB_DQS_DN<6>")
	)
	(segment
		(start 304.470308 -219.130372)
		(end 304.270156 -218.93022)
		(width 0.16002)
		(layer "In2.Cu")
		(net "M_B_CPU0_SB_DQS_DN<6>")
	)
	(segment
		(start 307.889148 -218.450668)
		(end 307.634386 -218.70543)
		(width 0.18288)
		(layer "In2.Cu")
		(net "M_B_CPU0_SB_DQS_DN<6>")
	)
	(segment
		(start 324.222872 -224.514156)
		(end 324.222872 -224.338134)
		(width 0.18288)
		(layer "In2.Cu")
		(net "M_B_CPU0_SB_DQS_DN<6>")
	)
	(segment
		(start 306.18303 -219.379546)
		(end 304.703734 -219.379546)
		(width 0.18288)
		(layer "In2.Cu")
		(net "M_B_CPU0_SB_DQS_DN<6>")
	)
	(segment
		(start 312.217054 -217.356436)
		(end 312.01741 -217.55608)
		(width 0.16002)
		(layer "In2.Cu")
		(net "M_B_CPU0_SB_DQS_DN<6>")
	)
	(segment
		(start 308.116986 -218.206574)
		(end 307.917342 -218.406218)
		(width 0.16002)
		(layer "In2.Cu")
		(net "M_B_CPU0_SB_DQS_DN<6>")
	)
	(segment
		(start 316.951106 -217.863928)
		(end 316.402466 -217.863928)
		(width 0.18288)
		(layer "In2.Cu")
		(net "M_B_CPU0_SB_DQS_DN<6>")
	)
	(segment
		(start 309.639462 -218.178634)
		(end 309.623206 -218.178634)
		(width 0.16002)
		(layer "In2.Cu")
		(net "M_B_CPU0_SB_DQS_DN<6>")
	)
	(segment
		(start 316.278006 -217.739468)
		(end 315.729366 -217.739468)
		(width 0.18288)
		(layer "In2.Cu")
		(net "M_B_CPU0_SB_DQS_DN<6>")
	)
	(segment
		(start 300.596046 -218.168474)
		(end 300.396402 -218.368118)
		(width 0.16002)
		(layer "In2.Cu")
		(net "M_B_CPU0_SB_DQS_DN<6>")
	)
	(segment
		(start 313.71286 -217.328242)
		(end 313.638946 -217.254328)
		(width 0.18288)
		(layer "In2.Cu")
		(net "M_B_CPU0_SB_DQS_DN<6>")
	)
	(segment
		(start 311.989216 -217.60053)
		(end 311.68721 -217.902536)
		(width 0.18288)
		(layer "In2.Cu")
		(net "M_B_CPU0_SB_DQS_DN<6>")
	)
	(segment
		(start 300.396402 -218.368118)
		(end 300.396402 -218.384374)
		(width 0.16002)
		(layer "In2.Cu")
		(net "M_B_CPU0_SB_DQS_DN<6>")
	)
	(segment
		(start 324.222872 -224.338134)
		(end 317.624206 -217.739468)
		(width 0.18288)
		(layer "In2.Cu")
		(net "M_B_CPU0_SB_DQS_DN<6>")
	)
	(segment
		(start 317.075566 -217.739468)
		(end 316.951106 -217.863928)
		(width 0.18288)
		(layer "In2.Cu")
		(net "M_B_CPU0_SB_DQS_DN<6>")
	)
	(segment
		(start 306.416456 -219.14612)
		(end 306.388262 -219.174314)
		(width 0.16002)
		(layer "In2.Cu")
		(net "M_B_CPU0_SB_DQS_DN<6>")
	)
	(segment
		(start 313.741054 -217.356436)
		(end 313.71286 -217.328242)
		(width 0.16002)
		(layer "In2.Cu")
		(net "M_B_CPU0_SB_DQS_DN<6>")
	)
	(segment
		(start 326.126856 -226.242118)
		(end 325.738998 -225.85426)
		(width 0.18288)
		(layer "In2.Cu")
		(net "M_B_CPU0_SB_DQS_DN<6>")
	)
	(segment
		(start 300.396402 -218.384374)
		(end 300.368208 -218.412568)
		(width 0.16002)
		(layer "In2.Cu")
		(net "M_B_CPU0_SB_DQS_DN<6>")
	)
	(segment
		(start 325.562976 -225.85426)
		(end 325.174864 -225.466148)
		(width 0.18288)
		(layer "In2.Cu")
		(net "M_B_CPU0_SB_DQS_DN<6>")
	)
	(segment
		(start 299.474636 -218.290902)
		(end 299.280326 -218.290902)
		(width 0.18288)
		(layer "In2.Cu")
		(net "M_B_CPU0_SB_DQS_DN<6>")
	)
	(segment
		(start 309.839106 -218.378278)
		(end 309.639462 -218.178634)
		(width 0.16002)
		(layer "In2.Cu")
		(net "M_B_CPU0_SB_DQS_DN<6>")
	)
	(segment
		(start 309.595012 -218.15044)
		(end 309.549038 -218.104466)
		(width 0.18288)
		(layer "In2.Cu")
		(net "M_B_CPU0_SB_DQS_DN<6>")
	)
	(segment
		(start 314.124086 -217.739468)
		(end 313.985148 -217.60053)
		(width 0.18288)
		(layer "In2.Cu")
		(net "M_B_CPU0_SB_DQS_DN<6>")
	)
	(segment
		(start 313.956954 -217.55608)
		(end 313.75731 -217.356436)
		(width 0.16002)
		(layer "In2.Cu")
		(net "M_B_CPU0_SB_DQS_DN<6>")
	)
	(segment
		(start 301.981362 -218.09075)
		(end 300.690026 -218.09075)
		(width 0.18288)
		(layer "In2.Cu")
		(net "M_B_CPU0_SB_DQS_DN<6>")
	)
	(segment
		(start 306.632356 -218.93022)
		(end 306.616608 -218.93022)
		(width 0.16002)
		(layer "In2.Cu")
		(net "M_B_CPU0_SB_DQS_DN<6>")
	)
	(segment
		(start 311.68721 -217.902536)
		(end 311.231534 -217.902536)
		(width 0.18288)
		(layer "In2.Cu")
		(net "M_B_CPU0_SB_DQS_DN<6>")
	)
	(segment
		(start 310.556402 -218.577668)
		(end 310.02224 -218.577668)
		(width 0.18288)
		(layer "In2.Cu")
		(net "M_B_CPU0_SB_DQS_DN<6>")
	)
	(segment
		(start 300.640496 -218.14028)
		(end 300.612302 -218.168474)
		(width 0.16002)
		(layer "In2.Cu")
		(net "M_B_CPU0_SB_DQS_DN<6>")
	)
	(segment
		(start 313.956954 -217.572336)
		(end 313.956954 -217.55608)
		(width 0.16002)
		(layer "In2.Cu")
		(net "M_B_CPU0_SB_DQS_DN<6>")
	)
	(segment
		(start 315.729366 -217.739468)
		(end 315.604906 -217.863928)
		(width 0.18288)
		(layer "In2.Cu")
		(net "M_B_CPU0_SB_DQS_DN<6>")
	)
	(segment
		(start 304.703734 -219.379546)
		(end 304.498502 -219.174314)
		(width 0.18288)
		(layer "In2.Cu")
		(net "M_B_CPU0_SB_DQS_DN<6>")
	)
	(segment
		(start 303.978818 -218.65463)
		(end 302.545242 -218.65463)
		(width 0.18288)
		(layer "In2.Cu")
		(net "M_B_CPU0_SB_DQS_DN<6>")
	)
	(segment
		(start 314.931806 -217.739468)
		(end 314.124086 -217.739468)
		(width 0.18288)
		(layer "In2.Cu")
		(net "M_B_CPU0_SB_DQS_DN<6>")
	)
	(segment
		(start 338.277708 -232.528364)
		(end 338.335112 -232.47096)
		(width 0.088646)
		(layer "In2.Cu")
		(net "M_B_CPU0_SB_DQS_DN<6>")
	)
	(segment
		(start 306.416456 -219.130372)
		(end 306.416456 -219.14612)
		(width 0.16002)
		(layer "In2.Cu")
		(net "M_B_CPU0_SB_DQS_DN<6>")
	)
	(segment
		(start 316.402466 -217.863928)
		(end 316.278006 -217.739468)
		(width 0.18288)
		(layer "In2.Cu")
		(net "M_B_CPU0_SB_DQS_DN<6>")
	)
	(segment
		(start 308.133242 -218.206574)
		(end 308.116986 -218.206574)
		(width 0.16002)
		(layer "In2.Cu")
		(net "M_B_CPU0_SB_DQS_DN<6>")
	)
	(segment
		(start 312.261504 -217.328242)
		(end 312.23331 -217.356436)
		(width 0.16002)
		(layer "In2.Cu")
		(net "M_B_CPU0_SB_DQS_DN<6>")
	)
	(segment
		(start 313.985148 -217.60053)
		(end 313.956954 -217.572336)
		(width 0.16002)
		(layer "In2.Cu")
		(net "M_B_CPU0_SB_DQS_DN<6>")
	)
	(segment
		(start 309.839106 -218.394534)
		(end 309.839106 -218.378278)
		(width 0.16002)
		(layer "In2.Cu")
		(net "M_B_CPU0_SB_DQS_DN<6>")
	)
	(segment
		(start 302.313086 -218.406218)
		(end 302.113442 -218.206574)
		(width 0.16002)
		(layer "In2.Cu")
		(net "M_B_CPU0_SB_DQS_DN<6>")
	)
	(segment
		(start 306.388262 -219.174314)
		(end 306.18303 -219.379546)
		(width 0.18288)
		(layer "In2.Cu")
		(net "M_B_CPU0_SB_DQS_DN<6>")
	)
	(segment
		(start 304.270156 -218.93022)
		(end 304.254408 -218.93022)
		(width 0.16002)
		(layer "In2.Cu")
		(net "M_B_CPU0_SB_DQS_DN<6>")
	)
	(segment
		(start 302.34128 -218.450668)
		(end 302.313086 -218.422474)
		(width 0.16002)
		(layer "In2.Cu")
		(net "M_B_CPU0_SB_DQS_DN<6>")
	)
	(segment
		(start 300.368208 -218.412568)
		(end 300.207426 -218.57335)
		(width 0.18288)
		(layer "In2.Cu")
		(net "M_B_CPU0_SB_DQS_DN<6>")
	)
	(segment
		(start 326.126856 -226.425506)
		(end 326.126856 -226.242118)
		(width 0.18288)
		(layer "In2.Cu")
		(net "M_B_CPU0_SB_DQS_DN<6>")
	)
	(segment
		(start 313.638946 -217.254328)
		(end 312.335418 -217.254328)
		(width 0.18288)
		(layer "In2.Cu")
		(net "M_B_CPU0_SB_DQS_DN<6>")
	)
	(segment
		(start 313.75731 -217.356436)
		(end 313.741054 -217.356436)
		(width 0.16002)
		(layer "In2.Cu")
		(net "M_B_CPU0_SB_DQS_DN<6>")
	)
	(segment
		(start 306.66055 -218.902026)
		(end 306.632356 -218.93022)
		(width 0.16002)
		(layer "In2.Cu")
		(net "M_B_CPU0_SB_DQS_DN<6>")
	)
	(segment
		(start 333.078582 -232.204006)
		(end 333.06385 -232.212642)
		(width 0.088646)
		(layer "In2.Cu")
		(net "M_B_CPU0_SB_DQS_DN<6>")
	)
	(segment
		(start 302.068992 -218.17838)
		(end 301.981362 -218.09075)
		(width 0.18288)
		(layer "In2.Cu")
		(net "M_B_CPU0_SB_DQS_DN<6>")
	)
	(segment
		(start 336.287364 -232.212642)
		(end 336.272632 -232.204006)
		(width 0.088646)
		(layer "In2.Cu")
		(net "M_B_CPU0_SB_DQS_DN<6>")
	)
	(segment
		(start 299.757084 -218.57335)
		(end 299.474636 -218.290902)
		(width 0.18288)
		(layer "In2.Cu")
		(net "M_B_CPU0_SB_DQS_DN<6>")
	)
	(segment
		(start 312.01741 -217.55608)
		(end 312.01741 -217.572336)
		(width 0.16002)
		(layer "In2.Cu")
		(net "M_B_CPU0_SB_DQS_DN<6>")
	)
	(segment
		(start 300.612302 -218.168474)
		(end 300.596046 -218.168474)
		(width 0.16002)
		(layer "In2.Cu")
		(net "M_B_CPU0_SB_DQS_DN<6>")
	)
	(segment
		(start 325.174864 -225.290126)
		(end 324.787006 -224.902268)
		(width 0.18288)
		(layer "In2.Cu")
		(net "M_B_CPU0_SB_DQS_DN<6>")
	)
	(segment
		(start 302.313086 -218.422474)
		(end 302.313086 -218.406218)
		(width 0.16002)
		(layer "In2.Cu")
		(net "M_B_CPU0_SB_DQS_DN<6>")
	)
	(segment
		(start 317.624206 -217.739468)
		(end 317.075566 -217.739468)
		(width 0.18288)
		(layer "In2.Cu")
		(net "M_B_CPU0_SB_DQS_DN<6>")
	)
	(segment
		(start 308.161436 -218.17838)
		(end 308.133242 -218.206574)
		(width 0.16002)
		(layer "In2.Cu")
		(net "M_B_CPU0_SB_DQS_DN<6>")
	)
	(segment
		(start 304.226214 -218.902026)
		(end 303.978818 -218.65463)
		(width 0.18288)
		(layer "In2.Cu")
		(net "M_B_CPU0_SB_DQS_DN<6>")
	)
	(segment
		(start 315.604906 -217.863928)
		(end 315.056266 -217.863928)
		(width 0.18288)
		(layer "In2.Cu")
		(net "M_B_CPU0_SB_DQS_DN<6>")
	)
	(segment
		(start 309.623206 -218.178634)
		(end 309.595012 -218.15044)
		(width 0.16002)
		(layer "In2.Cu")
		(net "M_B_CPU0_SB_DQS_DN<6>")
	)
	(segment
		(start 331.938884 -232.153206)
		(end 331.649578 -231.863392)
		(width 0.088646)
		(layer "In2.Cu")
		(net "M_B_CPU0_SB_DQS_DN<6>")
	)
	(segment
		(start 304.498502 -219.174314)
		(end 304.470308 -219.14612)
		(width 0.16002)
		(layer "In2.Cu")
		(net "M_B_CPU0_SB_DQS_DN<6>")
	)
	(segment
		(start 312.335418 -217.254328)
		(end 312.261504 -217.328242)
		(width 0.18288)
		(layer "In2.Cu")
		(net "M_B_CPU0_SB_DQS_DN<6>")
	)
	(segment
		(start 337.227164 -232.212642)
		(end 337.212432 -232.204006)
		(width 0.088646)
		(layer "In2.Cu")
		(net "M_B_CPU0_SB_DQS_DN<6>")
	)
	(segment
		(start 300.207426 -218.57335)
		(end 299.757084 -218.57335)
		(width 0.18288)
		(layer "In2.Cu")
		(net "M_B_CPU0_SB_DQS_DN<6>")
	)
	(segment
		(start 307.917342 -218.406218)
		(end 307.917342 -218.422474)
		(width 0.16002)
		(layer "In2.Cu")
		(net "M_B_CPU0_SB_DQS_DN<6>")
	)
	(segment
		(start 324.787006 -224.902268)
		(end 324.610984 -224.902268)
		(width 0.18288)
		(layer "In2.Cu")
		(net "M_B_CPU0_SB_DQS_DN<6>")
	)
	(segment
		(start 315.056266 -217.863928)
		(end 314.931806 -217.739468)
		(width 0.18288)
		(layer "In2.Cu")
		(net "M_B_CPU0_SB_DQS_DN<6>")
	)
	(segment
		(start 331.564742 -231.863392)
		(end 326.126856 -226.425506)
		(width 0.18288)
		(layer "In2.Cu")
		(net "M_B_CPU0_SB_DQS_DN<6>")
	)
	(segment
		(start 334.018636 -232.204006)
		(end 334.008222 -232.210102)
		(width 0.088646)
		(layer "In2.Cu")
		(net "M_B_CPU0_SB_DQS_DN<6>")
	)
	(segment
		(start 312.23331 -217.356436)
		(end 312.217054 -217.356436)
		(width 0.16002)
		(layer "In2.Cu")
		(net "M_B_CPU0_SB_DQS_DN<6>")
	)
	(arc
		(start 334.958436 -232.204006)
		(mid 334.675734 -232.279782)
		(end 334.393032 -232.204006)
		(width 0.088646)
		(layer "In2.Cu")
		(net "M_B_CPU0_SB_DQS_DN<6>")
	)
	(arc
		(start 335.898236 -232.204006)
		(mid 335.615534 -232.279782)
		(end 335.332832 -232.204006)
		(width 0.088646)
		(layer "In2.Cu")
		(net "M_B_CPU0_SB_DQS_DN<6>")
	)
	(arc
		(start 337.212432 -232.204006)
		(mid 337.025234 -232.153863)
		(end 336.838036 -232.204006)
		(width 0.088646)
		(layer "In2.Cu")
		(net "M_B_CPU0_SB_DQS_DN<6>")
	)
	(arc
		(start 336.838036 -232.204006)
		(mid 336.563837 -232.279841)
		(end 336.287364 -232.212642)
		(width 0.088646)
		(layer "In2.Cu")
		(net "M_B_CPU0_SB_DQS_DN<6>")
	)
	(arc
		(start 337.777836 -232.204006)
		(mid 337.503637 -232.279841)
		(end 337.227164 -232.212642)
		(width 0.088646)
		(layer "In2.Cu")
		(net "M_B_CPU0_SB_DQS_DN<6>")
	)
	(arc
		(start 332.513178 -232.204006)
		(mid 332.422922 -232.166284)
		(end 332.32598 -232.153206)
		(width 0.088646)
		(layer "In2.Cu")
		(net "M_B_CPU0_SB_DQS_DN<6>")
	)
	(arc
		(start 334.008222 -232.210102)
		(mid 333.72979 -232.279948)
		(end 333.452978 -232.204006)
		(width 0.088646)
		(layer "In2.Cu")
		(net "M_B_CPU0_SB_DQS_DN<6>")
	)
	(arc
		(start 333.452978 -232.204006)
		(mid 333.26578 -232.153863)
		(end 333.078582 -232.204006)
		(width 0.088646)
		(layer "In2.Cu")
		(net "M_B_CPU0_SB_DQS_DN<6>")
	)
	(arc
		(start 334.393032 -232.204006)
		(mid 334.205834 -232.153863)
		(end 334.018636 -232.204006)
		(width 0.088646)
		(layer "In2.Cu")
		(net "M_B_CPU0_SB_DQS_DN<6>")
	)
	(arc
		(start 338.335112 -232.47096)
		(mid 338.126829 -232.190614)
		(end 337.777836 -232.204006)
		(width 0.088646)
		(layer "In2.Cu")
		(net "M_B_CPU0_SB_DQS_DN<6>")
	)
	(arc
		(start 333.06385 -232.212642)
		(mid 332.787375 -232.279962)
		(end 332.513178 -232.204006)
		(width 0.088646)
		(layer "In2.Cu")
		(net "M_B_CPU0_SB_DQS_DN<6>")
	)
	(arc
		(start 336.272632 -232.204006)
		(mid 336.085434 -232.153863)
		(end 335.898236 -232.204006)
		(width 0.088646)
		(layer "In2.Cu")
		(net "M_B_CPU0_SB_DQS_DN<6>")
	)
	(arc
		(start 335.332832 -232.204006)
		(mid 335.145634 -232.153863)
		(end 334.958436 -232.204006)
		(width 0.088646)
		(layer "In2.Cu")
		(net "M_B_CPU0_SB_DQS_DN<6>")
	)
	(segment
		(start 295.142666 -227.491798)
		(end 295.000426 -227.491798)
		(width 0.20066)
		(layer "F.Cu")
		(net "M_B_CPU0_SB_DQS_DN<5>")
	)
	(segment
		(start 341.254334 -235.506006)
		(end 341.25408 -235.505752)
		(width 0.20066)
		(layer "F.Cu")
		(net "M_B_CPU0_SB_DQS_DN<5>")
	)
	(segment
		(start 297.147996 -227.655628)
		(end 296.444416 -227.655628)
		(width 0.20066)
		(layer "F.Cu")
		(net "M_B_CPU0_SB_DQS_DN<5>")
	)
	(segment
		(start 292.92296 -227.491798)
		(end 292.683184 -227.491798)
		(width 0.101854)
		(layer "F.Cu")
		(net "M_B_CPU0_SB_DQS_DN<5>")
	)
	(segment
		(start 296.444416 -227.655628)
		(end 295.8084 -227.230686)
		(width 0.20066)
		(layer "F.Cu")
		(net "M_B_CPU0_SB_DQS_DN<5>")
	)
	(segment
		(start 295.000426 -227.491798)
		(end 292.92296 -227.491798)
		(width 0.1016)
		(layer "F.Cu")
		(net "M_B_CPU0_SB_DQS_DN<5>")
	)
	(segment
		(start 297.899582 -227.91674)
		(end 297.409108 -227.91674)
		(width 0.20066)
		(layer "F.Cu")
		(net "M_B_CPU0_SB_DQS_DN<5>")
	)
	(segment
		(start 291.561774 -227.655628)
		(end 291.088572 -227.655628)
		(width 0.20066)
		(layer "F.Cu")
		(net "M_B_CPU0_SB_DQS_DN<5>")
	)
	(segment
		(start 291.984176 -227.233226)
		(end 291.561774 -227.655628)
		(width 0.20066)
		(layer "F.Cu")
		(net "M_B_CPU0_SB_DQS_DN<5>")
	)
	(segment
		(start 290.82746 -227.91674)
		(end 290.355782 -227.91674)
		(width 0.20066)
		(layer "F.Cu")
		(net "M_B_CPU0_SB_DQS_DN<5>")
	)
	(segment
		(start 295.403778 -227.230686)
		(end 295.142666 -227.491798)
		(width 0.20066)
		(layer "F.Cu")
		(net "M_B_CPU0_SB_DQS_DN<5>")
	)
	(segment
		(start 292.67531 -227.499672)
		(end 292.490398 -227.499672)
		(width 0.20066)
		(layer "F.Cu")
		(net "M_B_CPU0_SB_DQS_DN<5>")
	)
	(segment
		(start 341.25408 -235.505752)
		(end 341.25408 -234.970066)
		(width 0.20066)
		(layer "F.Cu")
		(net "M_B_CPU0_SB_DQS_DN<5>")
	)
	(segment
		(start 291.088572 -227.655628)
		(end 290.82746 -227.91674)
		(width 0.20066)
		(layer "F.Cu")
		(net "M_B_CPU0_SB_DQS_DN<5>")
	)
	(segment
		(start 292.223952 -227.233226)
		(end 291.984176 -227.233226)
		(width 0.20066)
		(layer "F.Cu")
		(net "M_B_CPU0_SB_DQS_DN<5>")
	)
	(segment
		(start 295.8084 -227.230686)
		(end 295.403778 -227.230686)
		(width 0.20066)
		(layer "F.Cu")
		(net "M_B_CPU0_SB_DQS_DN<5>")
	)
	(segment
		(start 297.409108 -227.91674)
		(end 297.147996 -227.655628)
		(width 0.20066)
		(layer "F.Cu")
		(net "M_B_CPU0_SB_DQS_DN<5>")
	)
	(segment
		(start 292.490398 -227.499672)
		(end 292.223952 -227.233226)
		(width 0.20066)
		(layer "F.Cu")
		(net "M_B_CPU0_SB_DQS_DN<5>")
	)
	(segment
		(start 299.004482 -227.91674)
		(end 297.899582 -227.91674)
		(width 0.20066)
		(layer "F.Cu")
		(net "M_B_CPU0_SB_DQS_DN<5>")
	)
	(segment
		(start 292.683184 -227.491798)
		(end 292.67531 -227.499672)
		(width 0.101854)
		(layer "F.Cu")
		(net "M_B_CPU0_SB_DQS_DN<5>")
	)
	(segment
		(start 332.326488 -234.7214)
		(end 331.770228 -234.7214)
		(width 0.088646)
		(layer "In4.Cu")
		(net "M_B_CPU0_SB_DQS_DN<5>")
	)
	(segment
		(start 299.02785 -227.91674)
		(end 299.004482 -227.91674)
		(width 0.18288)
		(layer "In4.Cu")
		(net "M_B_CPU0_SB_DQS_DN<5>")
	)
	(segment
		(start 321.814952 -233.766106)
		(end 321.814952 -233.590084)
		(width 0.18288)
		(layer "In4.Cu")
		(net "M_B_CPU0_SB_DQS_DN<5>")
	)
	(segment
		(start 339.187282 -234.645708)
		(end 339.176868 -234.651804)
		(width 0.088646)
		(layer "In4.Cu")
		(net "M_B_CPU0_SB_DQS_DN<5>")
	)
	(segment
		(start 331.024992 -234.672886)
		(end 330.743814 -234.672886)
		(width 0.088646)
		(layer "In4.Cu")
		(net "M_B_CPU0_SB_DQS_DN<5>")
	)
	(segment
		(start 341.566754 -234.970066)
		(end 341.624158 -234.912662)
		(width 0.088646)
		(layer "In4.Cu")
		(net "M_B_CPU0_SB_DQS_DN<5>")
	)
	(segment
		(start 319.52311 -231.298242)
		(end 319.347088 -231.298242)
		(width 0.18288)
		(layer "In4.Cu")
		(net "M_B_CPU0_SB_DQS_DN<5>")
	)
	(segment
		(start 310.457596 -225.522282)
		(end 310.188356 -225.791522)
		(width 0.18288)
		(layer "In4.Cu")
		(net "M_B_CPU0_SB_DQS_DN<5>")
	)
	(segment
		(start 315.476636 -227.251768)
		(end 314.569348 -227.251768)
		(width 0.18288)
		(layer "In4.Cu")
		(net "M_B_CPU0_SB_DQS_DN<5>")
	)
	(segment
		(start 303.605946 -226.621086)
		(end 301.855378 -226.621086)
		(width 0.18288)
		(layer "In4.Cu")
		(net "M_B_CPU0_SB_DQS_DN<5>")
	)
	(segment
		(start 312.980578 -227.233734)
		(end 312.523378 -226.776534)
		(width 0.18288)
		(layer "In4.Cu")
		(net "M_B_CPU0_SB_DQS_DN<5>")
	)
	(segment
		(start 322.37934 -234.154472)
		(end 322.203318 -234.154472)
		(width 0.18288)
		(layer "In4.Cu")
		(net "M_B_CPU0_SB_DQS_DN<5>")
	)
	(segment
		(start 321.814952 -233.590084)
		(end 321.427094 -233.202226)
		(width 0.18288)
		(layer "In4.Cu")
		(net "M_B_CPU0_SB_DQS_DN<5>")
	)
	(segment
		(start 318.958976 -230.91013)
		(end 318.958976 -230.734108)
		(width 0.18288)
		(layer "In4.Cu")
		(net "M_B_CPU0_SB_DQS_DN<5>")
	)
	(segment
		(start 311.865264 -225.522282)
		(end 310.457596 -225.522282)
		(width 0.18288)
		(layer "In4.Cu")
		(net "M_B_CPU0_SB_DQS_DN<5>")
	)
	(segment
		(start 314.569348 -227.251768)
		(end 314.326778 -227.494338)
		(width 0.18288)
		(layer "In4.Cu")
		(net "M_B_CPU0_SB_DQS_DN<5>")
	)
	(segment
		(start 331.770228 -234.7214)
		(end 331.634084 -234.857544)
		(width 0.088646)
		(layer "In4.Cu")
		(net "M_B_CPU0_SB_DQS_DN<5>")
	)
	(segment
		(start 331.20965 -234.857544)
		(end 331.024992 -234.672886)
		(width 0.088646)
		(layer "In4.Cu")
		(net "M_B_CPU0_SB_DQS_DN<5>")
	)
	(segment
		(start 320.86296 -232.814114)
		(end 320.86296 -232.638092)
		(width 0.18288)
		(layer "In4.Cu")
		(net "M_B_CPU0_SB_DQS_DN<5>")
	)
	(segment
		(start 299.250862 -227.824538)
		(end 299.02785 -227.91674)
		(width 0.18288)
		(layer "In4.Cu")
		(net "M_B_CPU0_SB_DQS_DN<5>")
	)
	(segment
		(start 335.428082 -234.645708)
		(end 335.41335 -234.654344)
		(width 0.088646)
		(layer "In4.Cu")
		(net "M_B_CPU0_SB_DQS_DN<5>")
	)
	(segment
		(start 322.203318 -234.154472)
		(end 321.814952 -233.766106)
		(width 0.18288)
		(layer "In4.Cu")
		(net "M_B_CPU0_SB_DQS_DN<5>")
	)
	(segment
		(start 310.188356 -225.791522)
		(end 309.800244 -225.791522)
		(width 0.18288)
		(layer "In4.Cu")
		(net "M_B_CPU0_SB_DQS_DN<5>")
	)
	(segment
		(start 301.855378 -226.621086)
		(end 300.651926 -227.824538)
		(width 0.18288)
		(layer "In4.Cu")
		(net "M_B_CPU0_SB_DQS_DN<5>")
	)
	(segment
		(start 319.347088 -231.298242)
		(end 318.958976 -230.91013)
		(width 0.18288)
		(layer "In4.Cu")
		(net "M_B_CPU0_SB_DQS_DN<5>")
	)
	(segment
		(start 318.958976 -230.734108)
		(end 315.476636 -227.251768)
		(width 0.18288)
		(layer "In4.Cu")
		(net "M_B_CPU0_SB_DQS_DN<5>")
	)
	(segment
		(start 306.749958 -225.51517)
		(end 306.162964 -225.51517)
		(width 0.18288)
		(layer "In4.Cu")
		(net "M_B_CPU0_SB_DQS_DN<5>")
	)
	(segment
		(start 307.38445 -224.880678)
		(end 306.749958 -225.51517)
		(width 0.18288)
		(layer "In4.Cu")
		(net "M_B_CPU0_SB_DQS_DN<5>")
	)
	(segment
		(start 341.066882 -234.645708)
		(end 341.05215 -234.654344)
		(width 0.088646)
		(layer "In4.Cu")
		(net "M_B_CPU0_SB_DQS_DN<5>")
	)
	(segment
		(start 312.523378 -226.180396)
		(end 311.865264 -225.522282)
		(width 0.18288)
		(layer "In4.Cu")
		(net "M_B_CPU0_SB_DQS_DN<5>")
	)
	(segment
		(start 319.910968 -231.862122)
		(end 319.910968 -231.6861)
		(width 0.18288)
		(layer "In4.Cu")
		(net "M_B_CPU0_SB_DQS_DN<5>")
	)
	(segment
		(start 333.548482 -234.645708)
		(end 333.53375 -234.654344)
		(width 0.088646)
		(layer "In4.Cu")
		(net "M_B_CPU0_SB_DQS_DN<5>")
	)
	(segment
		(start 330.648564 -234.73283)
		(end 322.957698 -234.73283)
		(width 0.18288)
		(layer "In4.Cu")
		(net "M_B_CPU0_SB_DQS_DN<5>")
	)
	(segment
		(start 320.475102 -232.250234)
		(end 320.29908 -232.250234)
		(width 0.18288)
		(layer "In4.Cu")
		(net "M_B_CPU0_SB_DQS_DN<5>")
	)
	(segment
		(start 309.532274 -225.523552)
		(end 308.808628 -225.523552)
		(width 0.18288)
		(layer "In4.Cu")
		(net "M_B_CPU0_SB_DQS_DN<5>")
	)
	(segment
		(start 306.162964 -225.51517)
		(end 304.668936 -227.009198)
		(width 0.18288)
		(layer "In4.Cu")
		(net "M_B_CPU0_SB_DQS_DN<5>")
	)
	(segment
		(start 330.68387 -234.73283)
		(end 330.648564 -234.73283)
		(width 0.088646)
		(layer "In4.Cu")
		(net "M_B_CPU0_SB_DQS_DN<5>")
	)
	(segment
		(start 334.488282 -234.645708)
		(end 334.47355 -234.654344)
		(width 0.088646)
		(layer "In4.Cu")
		(net "M_B_CPU0_SB_DQS_DN<5>")
	)
	(segment
		(start 303.994058 -227.009198)
		(end 303.605946 -226.621086)
		(width 0.18288)
		(layer "In4.Cu")
		(net "M_B_CPU0_SB_DQS_DN<5>")
	)
	(segment
		(start 300.651926 -227.824538)
		(end 299.250862 -227.824538)
		(width 0.18288)
		(layer "In4.Cu")
		(net "M_B_CPU0_SB_DQS_DN<5>")
	)
	(segment
		(start 312.523378 -226.776534)
		(end 312.523378 -226.180396)
		(width 0.18288)
		(layer "In4.Cu")
		(net "M_B_CPU0_SB_DQS_DN<5>")
	)
	(segment
		(start 308.808628 -225.523552)
		(end 308.165754 -224.880678)
		(width 0.18288)
		(layer "In4.Cu")
		(net "M_B_CPU0_SB_DQS_DN<5>")
	)
	(segment
		(start 304.668936 -227.009198)
		(end 303.994058 -227.009198)
		(width 0.18288)
		(layer "In4.Cu")
		(net "M_B_CPU0_SB_DQS_DN<5>")
	)
	(segment
		(start 314.326778 -227.494338)
		(end 313.896756 -227.494338)
		(width 0.18288)
		(layer "In4.Cu")
		(net "M_B_CPU0_SB_DQS_DN<5>")
	)
	(segment
		(start 320.86296 -232.638092)
		(end 320.475102 -232.250234)
		(width 0.18288)
		(layer "In4.Cu")
		(net "M_B_CPU0_SB_DQS_DN<5>")
	)
	(segment
		(start 313.636152 -227.233734)
		(end 312.980578 -227.233734)
		(width 0.18288)
		(layer "In4.Cu")
		(net "M_B_CPU0_SB_DQS_DN<5>")
	)
	(segment
		(start 338.247736 -234.645708)
		(end 338.237322 -234.651804)
		(width 0.088646)
		(layer "In4.Cu")
		(net "M_B_CPU0_SB_DQS_DN<5>")
	)
	(segment
		(start 319.910968 -231.6861)
		(end 319.52311 -231.298242)
		(width 0.18288)
		(layer "In4.Cu")
		(net "M_B_CPU0_SB_DQS_DN<5>")
	)
	(segment
		(start 321.427094 -233.202226)
		(end 321.251072 -233.202226)
		(width 0.18288)
		(layer "In4.Cu")
		(net "M_B_CPU0_SB_DQS_DN<5>")
	)
	(segment
		(start 341.25408 -234.970066)
		(end 341.566754 -234.970066)
		(width 0.088646)
		(layer "In4.Cu")
		(net "M_B_CPU0_SB_DQS_DN<5>")
	)
	(segment
		(start 321.251072 -233.202226)
		(end 320.86296 -232.814114)
		(width 0.18288)
		(layer "In4.Cu")
		(net "M_B_CPU0_SB_DQS_DN<5>")
	)
	(segment
		(start 308.165754 -224.880678)
		(end 307.38445 -224.880678)
		(width 0.18288)
		(layer "In4.Cu")
		(net "M_B_CPU0_SB_DQS_DN<5>")
	)
	(segment
		(start 309.800244 -225.791522)
		(end 309.532274 -225.523552)
		(width 0.18288)
		(layer "In4.Cu")
		(net "M_B_CPU0_SB_DQS_DN<5>")
	)
	(segment
		(start 320.29908 -232.250234)
		(end 319.910968 -231.862122)
		(width 0.18288)
		(layer "In4.Cu")
		(net "M_B_CPU0_SB_DQS_DN<5>")
	)
	(segment
		(start 331.634084 -234.857544)
		(end 331.20965 -234.857544)
		(width 0.088646)
		(layer "In4.Cu")
		(net "M_B_CPU0_SB_DQS_DN<5>")
	)
	(segment
		(start 322.957698 -234.73283)
		(end 322.37934 -234.154472)
		(width 0.18288)
		(layer "In4.Cu")
		(net "M_B_CPU0_SB_DQS_DN<5>")
	)
	(segment
		(start 313.896756 -227.494338)
		(end 313.636152 -227.233734)
		(width 0.18288)
		(layer "In4.Cu")
		(net "M_B_CPU0_SB_DQS_DN<5>")
	)
	(segment
		(start 336.367882 -234.645708)
		(end 336.35315 -234.654344)
		(width 0.088646)
		(layer "In4.Cu")
		(net "M_B_CPU0_SB_DQS_DN<5>")
	)
	(segment
		(start 340.127082 -234.645708)
		(end 340.11235 -234.654344)
		(width 0.088646)
		(layer "In4.Cu")
		(net "M_B_CPU0_SB_DQS_DN<5>")
	)
	(segment
		(start 337.307682 -234.645708)
		(end 337.29295 -234.654344)
		(width 0.088646)
		(layer "In4.Cu")
		(net "M_B_CPU0_SB_DQS_DN<5>")
	)
	(segment
		(start 330.743814 -234.672886)
		(end 330.68387 -234.73283)
		(width 0.088646)
		(layer "In4.Cu")
		(net "M_B_CPU0_SB_DQS_DN<5>")
	)
	(arc
		(start 339.176868 -234.651804)
		(mid 338.89869 -234.721527)
		(end 338.622132 -234.645708)
		(width 0.088646)
		(layer "In4.Cu")
		(net "M_B_CPU0_SB_DQS_DN<5>")
	)
	(arc
		(start 340.501478 -234.645708)
		(mid 340.31428 -234.595565)
		(end 340.127082 -234.645708)
		(width 0.088646)
		(layer "In4.Cu")
		(net "M_B_CPU0_SB_DQS_DN<5>")
	)
	(arc
		(start 338.237322 -234.651804)
		(mid 337.95889 -234.72165)
		(end 337.682078 -234.645708)
		(width 0.088646)
		(layer "In4.Cu")
		(net "M_B_CPU0_SB_DQS_DN<5>")
	)
	(arc
		(start 336.35315 -234.654344)
		(mid 336.076675 -234.721664)
		(end 335.802478 -234.645708)
		(width 0.088646)
		(layer "In4.Cu")
		(net "M_B_CPU0_SB_DQS_DN<5>")
	)
	(arc
		(start 335.41335 -234.654344)
		(mid 335.136875 -234.721664)
		(end 334.862678 -234.645708)
		(width 0.088646)
		(layer "In4.Cu")
		(net "M_B_CPU0_SB_DQS_DN<5>")
	)
	(arc
		(start 335.802478 -234.645708)
		(mid 335.61528 -234.595565)
		(end 335.428082 -234.645708)
		(width 0.088646)
		(layer "In4.Cu")
		(net "M_B_CPU0_SB_DQS_DN<5>")
	)
	(arc
		(start 341.05215 -234.654344)
		(mid 340.775675 -234.721664)
		(end 340.501478 -234.645708)
		(width 0.088646)
		(layer "In4.Cu")
		(net "M_B_CPU0_SB_DQS_DN<5>")
	)
	(arc
		(start 337.682078 -234.645708)
		(mid 337.49488 -234.595565)
		(end 337.307682 -234.645708)
		(width 0.088646)
		(layer "In4.Cu")
		(net "M_B_CPU0_SB_DQS_DN<5>")
	)
	(arc
		(start 340.11235 -234.654344)
		(mid 339.835875 -234.721664)
		(end 339.561678 -234.645708)
		(width 0.088646)
		(layer "In4.Cu")
		(net "M_B_CPU0_SB_DQS_DN<5>")
	)
	(arc
		(start 332.983078 -234.645708)
		(mid 332.79588 -234.595565)
		(end 332.608682 -234.645708)
		(width 0.088646)
		(layer "In4.Cu")
		(net "M_B_CPU0_SB_DQS_DN<5>")
	)
	(arc
		(start 333.53375 -234.654344)
		(mid 333.257275 -234.721664)
		(end 332.983078 -234.645708)
		(width 0.088646)
		(layer "In4.Cu")
		(net "M_B_CPU0_SB_DQS_DN<5>")
	)
	(arc
		(start 334.47355 -234.654344)
		(mid 334.197075 -234.721664)
		(end 333.922878 -234.645708)
		(width 0.088646)
		(layer "In4.Cu")
		(net "M_B_CPU0_SB_DQS_DN<5>")
	)
	(arc
		(start 332.608682 -234.645708)
		(mid 332.472558 -234.702084)
		(end 332.326488 -234.7214)
		(width 0.088646)
		(layer "In4.Cu")
		(net "M_B_CPU0_SB_DQS_DN<5>")
	)
	(arc
		(start 338.622132 -234.645708)
		(mid 338.434934 -234.595565)
		(end 338.247736 -234.645708)
		(width 0.088646)
		(layer "In4.Cu")
		(net "M_B_CPU0_SB_DQS_DN<5>")
	)
	(arc
		(start 333.922878 -234.645708)
		(mid 333.73568 -234.595565)
		(end 333.548482 -234.645708)
		(width 0.088646)
		(layer "In4.Cu")
		(net "M_B_CPU0_SB_DQS_DN<5>")
	)
	(arc
		(start 337.29295 -234.654344)
		(mid 337.016475 -234.721664)
		(end 336.742278 -234.645708)
		(width 0.088646)
		(layer "In4.Cu")
		(net "M_B_CPU0_SB_DQS_DN<5>")
	)
	(arc
		(start 336.742278 -234.645708)
		(mid 336.55508 -234.595565)
		(end 336.367882 -234.645708)
		(width 0.088646)
		(layer "In4.Cu")
		(net "M_B_CPU0_SB_DQS_DN<5>")
	)
	(arc
		(start 341.624158 -234.912662)
		(mid 341.415875 -234.632316)
		(end 341.066882 -234.645708)
		(width 0.088646)
		(layer "In4.Cu")
		(net "M_B_CPU0_SB_DQS_DN<5>")
	)
	(arc
		(start 334.862678 -234.645708)
		(mid 334.67548 -234.595565)
		(end 334.488282 -234.645708)
		(width 0.088646)
		(layer "In4.Cu")
		(net "M_B_CPU0_SB_DQS_DN<5>")
	)
	(arc
		(start 339.561678 -234.645708)
		(mid 339.37448 -234.595565)
		(end 339.187282 -234.645708)
		(width 0.088646)
		(layer "In4.Cu")
		(net "M_B_CPU0_SB_DQS_DN<5>")
	)
	(segment
		(start 292.223952 -236.58322)
		(end 291.984176 -236.58322)
		(width 0.20066)
		(layer "F.Cu")
		(net "M_B_CPU0_SB_DQS_DN<4>")
	)
	(segment
		(start 295.403778 -236.58068)
		(end 295.142666 -236.841792)
		(width 0.20066)
		(layer "F.Cu")
		(net "M_B_CPU0_SB_DQS_DN<4>")
	)
	(segment
		(start 292.92296 -236.841792)
		(end 292.683184 -236.841792)
		(width 0.101854)
		(layer "F.Cu")
		(net "M_B_CPU0_SB_DQS_DN<4>")
	)
	(segment
		(start 292.67531 -236.849666)
		(end 292.490398 -236.849666)
		(width 0.20066)
		(layer "F.Cu")
		(net "M_B_CPU0_SB_DQS_DN<4>")
	)
	(segment
		(start 296.444416 -237.005622)
		(end 295.8084 -236.58068)
		(width 0.20066)
		(layer "F.Cu")
		(net "M_B_CPU0_SB_DQS_DN<4>")
	)
	(segment
		(start 297.409108 -237.266734)
		(end 297.147996 -237.005622)
		(width 0.20066)
		(layer "F.Cu")
		(net "M_B_CPU0_SB_DQS_DN<4>")
	)
	(segment
		(start 299.004482 -237.266734)
		(end 297.899582 -237.266734)
		(width 0.20066)
		(layer "F.Cu")
		(net "M_B_CPU0_SB_DQS_DN<4>")
	)
	(segment
		(start 292.683184 -236.841792)
		(end 292.67531 -236.849666)
		(width 0.101854)
		(layer "F.Cu")
		(net "M_B_CPU0_SB_DQS_DN<4>")
	)
	(segment
		(start 292.490398 -236.849666)
		(end 292.223952 -236.58322)
		(width 0.20066)
		(layer "F.Cu")
		(net "M_B_CPU0_SB_DQS_DN<4>")
	)
	(segment
		(start 297.899582 -237.266734)
		(end 297.409108 -237.266734)
		(width 0.20066)
		(layer "F.Cu")
		(net "M_B_CPU0_SB_DQS_DN<4>")
	)
	(segment
		(start 297.147996 -237.005622)
		(end 296.444416 -237.005622)
		(width 0.20066)
		(layer "F.Cu")
		(net "M_B_CPU0_SB_DQS_DN<4>")
	)
	(segment
		(start 291.984176 -236.58322)
		(end 291.561774 -237.005622)
		(width 0.20066)
		(layer "F.Cu")
		(net "M_B_CPU0_SB_DQS_DN<4>")
	)
	(segment
		(start 295.142666 -236.841792)
		(end 295.000426 -236.841792)
		(width 0.20066)
		(layer "F.Cu")
		(net "M_B_CPU0_SB_DQS_DN<4>")
	)
	(segment
		(start 295.000426 -236.841792)
		(end 292.92296 -236.841792)
		(width 0.1016)
		(layer "F.Cu")
		(net "M_B_CPU0_SB_DQS_DN<4>")
	)
	(segment
		(start 338.90458 -242.295172)
		(end 338.904834 -242.294918)
		(width 0.20066)
		(layer "F.Cu")
		(net "M_B_CPU0_SB_DQS_DN<4>")
	)
	(segment
		(start 295.8084 -236.58068)
		(end 295.403778 -236.58068)
		(width 0.20066)
		(layer "F.Cu")
		(net "M_B_CPU0_SB_DQS_DN<4>")
	)
	(segment
		(start 291.088572 -237.005622)
		(end 290.82746 -237.266734)
		(width 0.20066)
		(layer "F.Cu")
		(net "M_B_CPU0_SB_DQS_DN<4>")
	)
	(segment
		(start 291.561774 -237.005622)
		(end 291.088572 -237.005622)
		(width 0.20066)
		(layer "F.Cu")
		(net "M_B_CPU0_SB_DQS_DN<4>")
	)
	(segment
		(start 290.82746 -237.266734)
		(end 290.355782 -237.266734)
		(width 0.20066)
		(layer "F.Cu")
		(net "M_B_CPU0_SB_DQS_DN<4>")
	)
	(segment
		(start 338.90458 -242.830858)
		(end 338.90458 -242.295172)
		(width 0.20066)
		(layer "F.Cu")
		(net "M_B_CPU0_SB_DQS_DN<4>")
	)
	(segment
		(start 307.94452 -238.710724)
		(end 307.744368 -238.510572)
		(width 0.16002)
		(layer "In2.Cu")
		(net "M_B_CPU0_SB_DQS_DN<4>")
	)
	(segment
		(start 314.343034 -237.46333)
		(end 314.20435 -237.602014)
		(width 0.18288)
		(layer "In2.Cu")
		(net "M_B_CPU0_SB_DQS_DN<4>")
	)
	(segment
		(start 303.84369 -237.21949)
		(end 302.412654 -237.21949)
		(width 0.18288)
		(layer "In2.Cu")
		(net "M_B_CPU0_SB_DQS_DN<4>")
	)
	(segment
		(start 302.412654 -237.21949)
		(end 302.2092 -237.016036)
		(width 0.18288)
		(layer "In2.Cu")
		(net "M_B_CPU0_SB_DQS_DN<4>")
	)
	(segment
		(start 306.416456 -237.83036)
		(end 306.416456 -237.846108)
		(width 0.16002)
		(layer "In2.Cu")
		(net "M_B_CPU0_SB_DQS_DN<4>")
	)
	(segment
		(start 306.752498 -237.510066)
		(end 306.66055 -237.602014)
		(width 0.18288)
		(layer "In2.Cu")
		(net "M_B_CPU0_SB_DQS_DN<4>")
	)
	(segment
		(start 308.124098 -238.90605)
		(end 307.972714 -238.754666)
		(width 0.18288)
		(layer "In2.Cu")
		(net "M_B_CPU0_SB_DQS_DN<4>")
	)
	(segment
		(start 319.429384 -239.686592)
		(end 317.65113 -238.949992)
		(width 0.18288)
		(layer "In2.Cu")
		(net "M_B_CPU0_SB_DQS_DN<4>")
	)
	(segment
		(start 311.828688 -237.660688)
		(end 311.800494 -237.632494)
		(width 0.16002)
		(layer "In2.Cu")
		(net "M_B_CPU0_SB_DQS_DN<4>")
	)
	(segment
		(start 333.547974 -242.78463)
		(end 333.53756 -242.790726)
		(width 0.088646)
		(layer "In2.Cu")
		(net "M_B_CPU0_SB_DQS_DN<4>")
	)
	(segment
		(start 307.94452 -238.726472)
		(end 307.94452 -238.710724)
		(width 0.16002)
		(layer "In2.Cu")
		(net "M_B_CPU0_SB_DQS_DN<4>")
	)
	(segment
		(start 312.072782 -237.904782)
		(end 312.044588 -237.876588)
		(width 0.16002)
		(layer "In2.Cu")
		(net "M_B_CPU0_SB_DQS_DN<4>")
	)
	(segment
		(start 312.044588 -237.876588)
		(end 312.044588 -237.86084)
		(width 0.16002)
		(layer "In2.Cu")
		(net "M_B_CPU0_SB_DQS_DN<4>")
	)
	(segment
		(start 301.965106 -236.771942)
		(end 301.936912 -236.743748)
		(width 0.16002)
		(layer "In2.Cu")
		(net "M_B_CPU0_SB_DQS_DN<4>")
	)
	(segment
		(start 300.724062 -236.769402)
		(end 300.707806 -236.769402)
		(width 0.16002)
		(layer "In2.Cu")
		(net "M_B_CPU0_SB_DQS_DN<4>")
	)
	(segment
		(start 337.307682 -242.78463)
		(end 337.29295 -242.793266)
		(width 0.088646)
		(layer "In2.Cu")
		(net "M_B_CPU0_SB_DQS_DN<4>")
	)
	(segment
		(start 301.936912 -236.743748)
		(end 301.739554 -236.54639)
		(width 0.18288)
		(layer "In2.Cu")
		(net "M_B_CPU0_SB_DQS_DN<4>")
	)
	(segment
		(start 313.932062 -237.874302)
		(end 313.750198 -238.056166)
		(width 0.18288)
		(layer "In2.Cu")
		(net "M_B_CPU0_SB_DQS_DN<4>")
	)
	(segment
		(start 309.831994 -238.724186)
		(end 309.65013 -238.90605)
		(width 0.18288)
		(layer "In2.Cu")
		(net "M_B_CPU0_SB_DQS_DN<4>")
	)
	(segment
		(start 310.104282 -238.451898)
		(end 310.076088 -238.480092)
		(width 0.16002)
		(layer "In2.Cu")
		(net "M_B_CPU0_SB_DQS_DN<4>")
	)
	(segment
		(start 317.65113 -238.949992)
		(end 317.650876 -238.949992)
		(width 0.18288)
		(layer "In2.Cu")
		(net "M_B_CPU0_SB_DQS_DN<4>")
	)
	(segment
		(start 300.508162 -236.969046)
		(end 300.508162 -236.985302)
		(width 0.16002)
		(layer "In2.Cu")
		(net "M_B_CPU0_SB_DQS_DN<4>")
	)
	(segment
		(start 306.22367 -238.038894)
		(end 304.663094 -238.038894)
		(width 0.18288)
		(layer "In2.Cu")
		(net "M_B_CPU0_SB_DQS_DN<4>")
	)
	(segment
		(start 331.004164 -242.841526)
		(end 322.584826 -242.841526)
		(width 0.18288)
		(layer "In2.Cu")
		(net "M_B_CPU0_SB_DQS_DN<4>")
	)
	(segment
		(start 311.844436 -237.660688)
		(end 311.828688 -237.660688)
		(width 0.16002)
		(layer "In2.Cu")
		(net "M_B_CPU0_SB_DQS_DN<4>")
	)
	(segment
		(start 331.854302 -242.733322)
		(end 331.572108 -242.733322)
		(width 0.088646)
		(layer "In2.Cu")
		(net "M_B_CPU0_SB_DQS_DN<4>")
	)
	(segment
		(start 312.224166 -238.056166)
		(end 312.072782 -237.904782)
		(width 0.18288)
		(layer "In2.Cu")
		(net "M_B_CPU0_SB_DQS_DN<4>")
	)
	(segment
		(start 333.562452 -242.776248)
		(end 333.547974 -242.78463)
		(width 0.088646)
		(layer "In2.Cu")
		(net "M_B_CPU0_SB_DQS_DN<4>")
	)
	(segment
		(start 307.365146 -238.147098)
		(end 307.365146 -237.845346)
		(width 0.18288)
		(layer "In2.Cu")
		(net "M_B_CPU0_SB_DQS_DN<4>")
	)
	(segment
		(start 311.05221 -237.50397)
		(end 310.104282 -238.451898)
		(width 0.18288)
		(layer "In2.Cu")
		(net "M_B_CPU0_SB_DQS_DN<4>")
	)
	(segment
		(start 307.972714 -238.754666)
		(end 307.94452 -238.726472)
		(width 0.16002)
		(layer "In2.Cu")
		(net "M_B_CPU0_SB_DQS_DN<4>")
	)
	(segment
		(start 307.744368 -238.510572)
		(end 307.72862 -238.510572)
		(width 0.16002)
		(layer "In2.Cu")
		(net "M_B_CPU0_SB_DQS_DN<4>")
	)
	(segment
		(start 306.616608 -237.630208)
		(end 306.416456 -237.83036)
		(width 0.16002)
		(layer "In2.Cu")
		(net "M_B_CPU0_SB_DQS_DN<4>")
	)
	(segment
		(start 338.591906 -242.294918)
		(end 338.526628 -242.360196)
		(width 0.088646)
		(layer "In2.Cu")
		(net "M_B_CPU0_SB_DQS_DN<4>")
	)
	(segment
		(start 313.960256 -237.846108)
		(end 313.932062 -237.874302)
		(width 0.16002)
		(layer "In2.Cu")
		(net "M_B_CPU0_SB_DQS_DN<4>")
	)
	(segment
		(start 336.374486 -242.78082)
		(end 336.368136 -242.78463)
		(width 0.088646)
		(layer "In2.Cu")
		(net "M_B_CPU0_SB_DQS_DN<4>")
	)
	(segment
		(start 338.247482 -242.78463)
		(end 338.23275 -242.793266)
		(width 0.088646)
		(layer "In2.Cu")
		(net "M_B_CPU0_SB_DQS_DN<4>")
	)
	(segment
		(start 314.20435 -237.602014)
		(end 314.176156 -237.630208)
		(width 0.16002)
		(layer "In2.Cu")
		(net "M_B_CPU0_SB_DQS_DN<4>")
	)
	(segment
		(start 334.496664 -242.779804)
		(end 334.488282 -242.78463)
		(width 0.088646)
		(layer "In2.Cu")
		(net "M_B_CPU0_SB_DQS_DN<4>")
	)
	(segment
		(start 302.181006 -236.987842)
		(end 302.181006 -236.971586)
		(width 0.16002)
		(layer "In2.Cu")
		(net "M_B_CPU0_SB_DQS_DN<4>")
	)
	(segment
		(start 331.572108 -242.733322)
		(end 331.523594 -242.781836)
		(width 0.088646)
		(layer "In2.Cu")
		(net "M_B_CPU0_SB_DQS_DN<4>")
	)
	(segment
		(start 304.470308 -237.83036)
		(end 304.270156 -237.630208)
		(width 0.16002)
		(layer "In2.Cu")
		(net "M_B_CPU0_SB_DQS_DN<4>")
	)
	(segment
		(start 334.488282 -242.78463)
		(end 334.470248 -242.795044)
		(width 0.088646)
		(layer "In2.Cu")
		(net "M_B_CPU0_SB_DQS_DN<4>")
	)
	(segment
		(start 312.044588 -237.86084)
		(end 311.844436 -237.660688)
		(width 0.16002)
		(layer "In2.Cu")
		(net "M_B_CPU0_SB_DQS_DN<4>")
	)
	(segment
		(start 313.960256 -237.83036)
		(end 313.960256 -237.846108)
		(width 0.16002)
		(layer "In2.Cu")
		(net "M_B_CPU0_SB_DQS_DN<4>")
	)
	(segment
		(start 322.584826 -242.841526)
		(end 322.370958 -242.627912)
		(width 0.18288)
		(layer "In2.Cu")
		(net "M_B_CPU0_SB_DQS_DN<4>")
	)
	(segment
		(start 304.226214 -237.602014)
		(end 303.84369 -237.21949)
		(width 0.18288)
		(layer "In2.Cu")
		(net "M_B_CPU0_SB_DQS_DN<4>")
	)
	(segment
		(start 314.49899 -237.46333)
		(end 314.343034 -237.46333)
		(width 0.18288)
		(layer "In2.Cu")
		(net "M_B_CPU0_SB_DQS_DN<4>")
	)
	(segment
		(start 313.750198 -238.056166)
		(end 312.224166 -238.056166)
		(width 0.18288)
		(layer "In2.Cu")
		(net "M_B_CPU0_SB_DQS_DN<4>")
	)
	(segment
		(start 307.365146 -237.845346)
		(end 307.029866 -237.510066)
		(width 0.18288)
		(layer "In2.Cu")
		(net "M_B_CPU0_SB_DQS_DN<4>")
	)
	(segment
		(start 314.160408 -237.630208)
		(end 313.960256 -237.83036)
		(width 0.16002)
		(layer "In2.Cu")
		(net "M_B_CPU0_SB_DQS_DN<4>")
	)
	(segment
		(start 306.66055 -237.602014)
		(end 306.632356 -237.630208)
		(width 0.16002)
		(layer "In2.Cu")
		(net "M_B_CPU0_SB_DQS_DN<4>")
	)
	(segment
		(start 310.06034 -238.480092)
		(end 309.860188 -238.680244)
		(width 0.16002)
		(layer "In2.Cu")
		(net "M_B_CPU0_SB_DQS_DN<4>")
	)
	(segment
		(start 338.904834 -242.294918)
		(end 338.591906 -242.294918)
		(width 0.088646)
		(layer "In2.Cu")
		(net "M_B_CPU0_SB_DQS_DN<4>")
	)
	(segment
		(start 300.707806 -236.769402)
		(end 300.508162 -236.969046)
		(width 0.16002)
		(layer "In2.Cu")
		(net "M_B_CPU0_SB_DQS_DN<4>")
	)
	(segment
		(start 307.029866 -237.510066)
		(end 306.752498 -237.510066)
		(width 0.18288)
		(layer "In2.Cu")
		(net "M_B_CPU0_SB_DQS_DN<4>")
	)
	(segment
		(start 299.290232 -236.980984)
		(end 299.004482 -237.266734)
		(width 0.18288)
		(layer "In2.Cu")
		(net "M_B_CPU0_SB_DQS_DN<4>")
	)
	(segment
		(start 332.608936 -242.78463)
		(end 332.603348 -242.787932)
		(width 0.088646)
		(layer "In2.Cu")
		(net "M_B_CPU0_SB_DQS_DN<4>")
	)
	(segment
		(start 311.67197 -237.50397)
		(end 311.05221 -237.50397)
		(width 0.18288)
		(layer "In2.Cu")
		(net "M_B_CPU0_SB_DQS_DN<4>")
	)
	(segment
		(start 322.370958 -242.627912)
		(end 319.429384 -239.686592)
		(width 0.18288)
		(layer "In2.Cu")
		(net "M_B_CPU0_SB_DQS_DN<4>")
	)
	(segment
		(start 300.752256 -236.741208)
		(end 300.724062 -236.769402)
		(width 0.16002)
		(layer "In2.Cu")
		(net "M_B_CPU0_SB_DQS_DN<4>")
	)
	(segment
		(start 336.368136 -242.78463)
		(end 336.353404 -242.793266)
		(width 0.088646)
		(layer "In2.Cu")
		(net "M_B_CPU0_SB_DQS_DN<4>")
	)
	(segment
		(start 331.063854 -242.781836)
		(end 331.004164 -242.841526)
		(width 0.088646)
		(layer "In2.Cu")
		(net "M_B_CPU0_SB_DQS_DN<4>")
	)
	(segment
		(start 311.800494 -237.632494)
		(end 311.67197 -237.50397)
		(width 0.18288)
		(layer "In2.Cu")
		(net "M_B_CPU0_SB_DQS_DN<4>")
	)
	(segment
		(start 314.176156 -237.630208)
		(end 314.160408 -237.630208)
		(width 0.16002)
		(layer "In2.Cu")
		(net "M_B_CPU0_SB_DQS_DN<4>")
	)
	(segment
		(start 309.860188 -238.695992)
		(end 309.831994 -238.724186)
		(width 0.16002)
		(layer "In2.Cu")
		(net "M_B_CPU0_SB_DQS_DN<4>")
	)
	(segment
		(start 301.739554 -236.54639)
		(end 300.947074 -236.54639)
		(width 0.18288)
		(layer "In2.Cu")
		(net "M_B_CPU0_SB_DQS_DN<4>")
	)
	(segment
		(start 302.2092 -237.016036)
		(end 302.181006 -236.987842)
		(width 0.16002)
		(layer "In2.Cu")
		(net "M_B_CPU0_SB_DQS_DN<4>")
	)
	(segment
		(start 300.947074 -236.54639)
		(end 300.752256 -236.741208)
		(width 0.18288)
		(layer "In2.Cu")
		(net "M_B_CPU0_SB_DQS_DN<4>")
	)
	(segment
		(start 336.376518 -242.779804)
		(end 336.374486 -242.78082)
		(width 0.088646)
		(layer "In2.Cu")
		(net "M_B_CPU0_SB_DQS_DN<4>")
	)
	(segment
		(start 306.632356 -237.630208)
		(end 306.616608 -237.630208)
		(width 0.16002)
		(layer "In2.Cu")
		(net "M_B_CPU0_SB_DQS_DN<4>")
	)
	(segment
		(start 307.700426 -238.482378)
		(end 307.365146 -238.147098)
		(width 0.18288)
		(layer "In2.Cu")
		(net "M_B_CPU0_SB_DQS_DN<4>")
	)
	(segment
		(start 300.479968 -237.013496)
		(end 300.317154 -237.17631)
		(width 0.18288)
		(layer "In2.Cu")
		(net "M_B_CPU0_SB_DQS_DN<4>")
	)
	(segment
		(start 299.664882 -237.17631)
		(end 299.469556 -236.980984)
		(width 0.18288)
		(layer "In2.Cu")
		(net "M_B_CPU0_SB_DQS_DN<4>")
	)
	(segment
		(start 304.663094 -238.038894)
		(end 304.498502 -237.874302)
		(width 0.18288)
		(layer "In2.Cu")
		(net "M_B_CPU0_SB_DQS_DN<4>")
	)
	(segment
		(start 300.508162 -236.985302)
		(end 300.479968 -237.013496)
		(width 0.16002)
		(layer "In2.Cu")
		(net "M_B_CPU0_SB_DQS_DN<4>")
	)
	(segment
		(start 302.181006 -236.971586)
		(end 301.981362 -236.771942)
		(width 0.16002)
		(layer "In2.Cu")
		(net "M_B_CPU0_SB_DQS_DN<4>")
	)
	(segment
		(start 331.523594 -242.781836)
		(end 331.063854 -242.781836)
		(width 0.088646)
		(layer "In2.Cu")
		(net "M_B_CPU0_SB_DQS_DN<4>")
	)
	(segment
		(start 309.65013 -238.90605)
		(end 308.124098 -238.90605)
		(width 0.18288)
		(layer "In2.Cu")
		(net "M_B_CPU0_SB_DQS_DN<4>")
	)
	(segment
		(start 304.470308 -237.846108)
		(end 304.470308 -237.83036)
		(width 0.16002)
		(layer "In2.Cu")
		(net "M_B_CPU0_SB_DQS_DN<4>")
	)
	(segment
		(start 304.498502 -237.874302)
		(end 304.470308 -237.846108)
		(width 0.16002)
		(layer "In2.Cu")
		(net "M_B_CPU0_SB_DQS_DN<4>")
	)
	(segment
		(start 307.72862 -238.510572)
		(end 307.700426 -238.482378)
		(width 0.16002)
		(layer "In2.Cu")
		(net "M_B_CPU0_SB_DQS_DN<4>")
	)
	(segment
		(start 304.270156 -237.630208)
		(end 304.254408 -237.630208)
		(width 0.16002)
		(layer "In2.Cu")
		(net "M_B_CPU0_SB_DQS_DN<4>")
	)
	(segment
		(start 300.317154 -237.17631)
		(end 299.664882 -237.17631)
		(width 0.18288)
		(layer "In2.Cu")
		(net "M_B_CPU0_SB_DQS_DN<4>")
	)
	(segment
		(start 306.388262 -237.874302)
		(end 306.22367 -238.038894)
		(width 0.18288)
		(layer "In2.Cu")
		(net "M_B_CPU0_SB_DQS_DN<4>")
	)
	(segment
		(start 317.650876 -238.949992)
		(end 315.211968 -237.939834)
		(width 0.18288)
		(layer "In2.Cu")
		(net "M_B_CPU0_SB_DQS_DN<4>")
	)
	(segment
		(start 306.416456 -237.846108)
		(end 306.388262 -237.874302)
		(width 0.16002)
		(layer "In2.Cu")
		(net "M_B_CPU0_SB_DQS_DN<4>")
	)
	(segment
		(start 304.254408 -237.630208)
		(end 304.226214 -237.602014)
		(width 0.16002)
		(layer "In2.Cu")
		(net "M_B_CPU0_SB_DQS_DN<4>")
	)
	(segment
		(start 301.981362 -236.771942)
		(end 301.965106 -236.771942)
		(width 0.16002)
		(layer "In2.Cu")
		(net "M_B_CPU0_SB_DQS_DN<4>")
	)
	(segment
		(start 299.469556 -236.980984)
		(end 299.290232 -236.980984)
		(width 0.18288)
		(layer "In2.Cu")
		(net "M_B_CPU0_SB_DQS_DN<4>")
	)
	(segment
		(start 315.211968 -237.939834)
		(end 314.49899 -237.46333)
		(width 0.18288)
		(layer "In2.Cu")
		(net "M_B_CPU0_SB_DQS_DN<4>")
	)
	(segment
		(start 309.860188 -238.680244)
		(end 309.860188 -238.695992)
		(width 0.16002)
		(layer "In2.Cu")
		(net "M_B_CPU0_SB_DQS_DN<4>")
	)
	(segment
		(start 332.603348 -242.787932)
		(end 332.596998 -242.791488)
		(width 0.088646)
		(layer "In2.Cu")
		(net "M_B_CPU0_SB_DQS_DN<4>")
	)
	(segment
		(start 310.076088 -238.480092)
		(end 310.06034 -238.480092)
		(width 0.16002)
		(layer "In2.Cu")
		(net "M_B_CPU0_SB_DQS_DN<4>")
	)
	(arc
		(start 338.23275 -242.793266)
		(mid 337.956309 -242.860432)
		(end 337.682078 -242.78463)
		(width 0.088646)
		(layer "In2.Cu")
		(net "M_B_CPU0_SB_DQS_DN<4>")
	)
	(arc
		(start 334.470248 -242.795044)
		(mid 334.19509 -242.860537)
		(end 333.922624 -242.78463)
		(width 0.088646)
		(layer "In2.Cu")
		(net "M_B_CPU0_SB_DQS_DN<4>")
	)
	(arc
		(start 333.53756 -242.790726)
		(mid 333.259636 -242.860296)
		(end 332.983332 -242.78463)
		(width 0.088646)
		(layer "In2.Cu")
		(net "M_B_CPU0_SB_DQS_DN<4>")
	)
	(arc
		(start 337.29295 -242.793266)
		(mid 337.016509 -242.860432)
		(end 336.742278 -242.78463)
		(width 0.088646)
		(layer "In2.Cu")
		(net "M_B_CPU0_SB_DQS_DN<4>")
	)
	(arc
		(start 332.042262 -242.784376)
		(mid 331.961903 -242.749455)
		(end 331.875638 -242.734084)
		(width 0.088646)
		(layer "In2.Cu")
		(net "M_B_CPU0_SB_DQS_DN<4>")
	)
	(arc
		(start 336.742278 -242.78463)
		(mid 336.560027 -242.734519)
		(end 336.376518 -242.779804)
		(width 0.088646)
		(layer "In2.Cu")
		(net "M_B_CPU0_SB_DQS_DN<4>")
	)
	(arc
		(start 333.922624 -242.78463)
		(mid 333.743614 -242.734333)
		(end 333.562452 -242.776248)
		(width 0.088646)
		(layer "In2.Cu")
		(net "M_B_CPU0_SB_DQS_DN<4>")
	)
	(arc
		(start 338.526628 -242.360196)
		(mid 338.52533 -242.37075)
		(end 338.523834 -242.381278)
		(width 0.088646)
		(layer "In2.Cu")
		(net "M_B_CPU0_SB_DQS_DN<4>")
	)
	(arc
		(start 338.523834 -242.381278)
		(mid 338.431552 -242.614412)
		(end 338.247482 -242.78463)
		(width 0.088646)
		(layer "In2.Cu")
		(net "M_B_CPU0_SB_DQS_DN<4>")
	)
	(arc
		(start 337.682078 -242.78463)
		(mid 337.49488 -242.734487)
		(end 337.307682 -242.78463)
		(width 0.088646)
		(layer "In2.Cu")
		(net "M_B_CPU0_SB_DQS_DN<4>")
	)
	(arc
		(start 335.428336 -242.78463)
		(mid 335.14538 -242.860499)
		(end 334.862424 -242.78463)
		(width 0.088646)
		(layer "In2.Cu")
		(net "M_B_CPU0_SB_DQS_DN<4>")
	)
	(arc
		(start 336.353404 -242.793266)
		(mid 336.076963 -242.860432)
		(end 335.802732 -242.78463)
		(width 0.088646)
		(layer "In2.Cu")
		(net "M_B_CPU0_SB_DQS_DN<4>")
	)
	(arc
		(start 332.596998 -242.791488)
		(mid 332.318702 -242.860585)
		(end 332.042262 -242.784376)
		(width 0.088646)
		(layer "In2.Cu")
		(net "M_B_CPU0_SB_DQS_DN<4>")
	)
	(arc
		(start 334.862424 -242.78463)
		(mid 334.680173 -242.734519)
		(end 334.496664 -242.779804)
		(width 0.088646)
		(layer "In2.Cu")
		(net "M_B_CPU0_SB_DQS_DN<4>")
	)
	(arc
		(start 331.875638 -242.734084)
		(mid 331.864975 -242.733549)
		(end 331.854302 -242.733322)
		(width 0.088646)
		(layer "In2.Cu")
		(net "M_B_CPU0_SB_DQS_DN<4>")
	)
	(arc
		(start 335.802732 -242.78463)
		(mid 335.615534 -242.734487)
		(end 335.428336 -242.78463)
		(width 0.088646)
		(layer "In2.Cu")
		(net "M_B_CPU0_SB_DQS_DN<4>")
	)
	(arc
		(start 332.983332 -242.78463)
		(mid 332.796134 -242.734487)
		(end 332.608936 -242.78463)
		(width 0.088646)
		(layer "In2.Cu")
		(net "M_B_CPU0_SB_DQS_DN<4>")
	)
	(segment
		(start 292.991794 -200.12787)
		(end 292.58514 -200.12787)
		(width 0.20066)
		(layer "F.Cu")
		(net "M_B_CPU0_SB_DQS_DN<3>")
	)
	(segment
		(start 292.159944 -200.553066)
		(end 291.973254 -200.553066)
		(width 0.20066)
		(layer "F.Cu")
		(net "M_B_CPU0_SB_DQS_DN<3>")
	)
	(segment
		(start 291.556694 -200.2917)
		(end 289.243008 -200.2917)
		(width 0.1016)
		(layer "F.Cu")
		(net "M_B_CPU0_SB_DQS_DN<3>")
	)
	(segment
		(start 332.796134 -225.739198)
		(end 332.796134 -225.203258)
		(width 0.20066)
		(layer "F.Cu")
		(net "M_B_CPU0_SB_DQS_DN<3>")
	)
	(segment
		(start 287.579308 -200.12787)
		(end 287.065466 -200.12787)
		(width 0.20066)
		(layer "F.Cu")
		(net "M_B_CPU0_SB_DQS_DN<3>")
	)
	(segment
		(start 289.23234 -200.281032)
		(end 289.231578 -200.281032)
		(width 0.101854)
		(layer "F.Cu")
		(net "M_B_CPU0_SB_DQS_DN<3>")
	)
	(segment
		(start 293.252906 -199.866758)
		(end 292.991794 -200.12787)
		(width 0.20066)
		(layer "F.Cu")
		(net "M_B_CPU0_SB_DQS_DN<3>")
	)
	(segment
		(start 288.755328 -200.553066)
		(end 288.215324 -200.553066)
		(width 0.20066)
		(layer "F.Cu")
		(net "M_B_CPU0_SB_DQS_DN<3>")
	)
	(segment
		(start 287.065466 -200.12787)
		(end 286.804354 -199.866758)
		(width 0.20066)
		(layer "F.Cu")
		(net "M_B_CPU0_SB_DQS_DN<3>")
	)
	(segment
		(start 289.027362 -200.281032)
		(end 288.755328 -200.553066)
		(width 0.20066)
		(layer "F.Cu")
		(net "M_B_CPU0_SB_DQS_DN<3>")
	)
	(segment
		(start 292.58514 -200.12787)
		(end 292.159944 -200.553066)
		(width 0.20066)
		(layer "F.Cu")
		(net "M_B_CPU0_SB_DQS_DN<3>")
	)
	(segment
		(start 291.973254 -200.553066)
		(end 291.711888 -200.2917)
		(width 0.20066)
		(layer "F.Cu")
		(net "M_B_CPU0_SB_DQS_DN<3>")
	)
	(segment
		(start 288.215324 -200.553066)
		(end 287.579308 -200.12787)
		(width 0.20066)
		(layer "F.Cu")
		(net "M_B_CPU0_SB_DQS_DN<3>")
	)
	(segment
		(start 293.799514 -199.866758)
		(end 293.252906 -199.866758)
		(width 0.20066)
		(layer "F.Cu")
		(net "M_B_CPU0_SB_DQS_DN<3>")
	)
	(segment
		(start 291.711888 -200.2917)
		(end 291.556694 -200.2917)
		(width 0.20066)
		(layer "F.Cu")
		(net "M_B_CPU0_SB_DQS_DN<3>")
	)
	(segment
		(start 286.804354 -199.866758)
		(end 286.255714 -199.866758)
		(width 0.20066)
		(layer "F.Cu")
		(net "M_B_CPU0_SB_DQS_DN<3>")
	)
	(segment
		(start 289.243008 -200.2917)
		(end 289.23234 -200.281032)
		(width 0.101854)
		(layer "F.Cu")
		(net "M_B_CPU0_SB_DQS_DN<3>")
	)
	(segment
		(start 289.231578 -200.281032)
		(end 289.027362 -200.281032)
		(width 0.20066)
		(layer "F.Cu")
		(net "M_B_CPU0_SB_DQS_DN<3>")
	)
	(segment
		(start 294.904414 -199.866758)
		(end 293.799514 -199.866758)
		(width 0.20066)
		(layer "F.Cu")
		(net "M_B_CPU0_SB_DQS_DN<3>")
	)
	(segment
		(start 303.917096 -199.766174)
		(end 303.239424 -200.443846)
		(width 0.18288)
		(layer "In4.Cu")
		(net "M_B_CPU0_SB_DQS_DN<3>")
	)
	(segment
		(start 312.105802 -199.766174)
		(end 303.917096 -199.766174)
		(width 0.18288)
		(layer "In4.Cu")
		(net "M_B_CPU0_SB_DQS_DN<3>")
	)
	(segment
		(start 332.542642 -224.947226)
		(end 332.321408 -224.819464)
		(width 0.088646)
		(layer "In4.Cu")
		(net "M_B_CPU0_SB_DQS_DN<3>")
	)
	(segment
		(start 319.35547 -207.35925)
		(end 319.145666 -206.85252)
		(width 0.18288)
		(layer "In4.Cu")
		(net "M_B_CPU0_SB_DQS_DN<3>")
	)
	(segment
		(start 332.796134 -225.203258)
		(end 332.79588 -225.203258)
		(width 0.088646)
		(layer "In4.Cu")
		(net "M_B_CPU0_SB_DQS_DN<3>")
	)
	(segment
		(start 332.79588 -225.203258)
		(end 332.791308 -225.195384)
		(width 0.088646)
		(layer "In4.Cu")
		(net "M_B_CPU0_SB_DQS_DN<3>")
	)
	(segment
		(start 322.094352 -213.64575)
		(end 321.931538 -213.57844)
		(width 0.18288)
		(layer "In4.Cu")
		(net "M_B_CPU0_SB_DQS_DN<3>")
	)
	(segment
		(start 322.446904 -214.822278)
		(end 322.2371 -214.315548)
		(width 0.18288)
		(layer "In4.Cu")
		(net "M_B_CPU0_SB_DQS_DN<3>")
	)
	(segment
		(start 295.162986 -200.12533)
		(end 294.904414 -199.866758)
		(width 0.18288)
		(layer "In4.Cu")
		(net "M_B_CPU0_SB_DQS_DN<3>")
	)
	(segment
		(start 322.609718 -214.889588)
		(end 322.446904 -214.822278)
		(width 0.18288)
		(layer "In4.Cu")
		(net "M_B_CPU0_SB_DQS_DN<3>")
	)
	(segment
		(start 320.548508 -209.914236)
		(end 320.385694 -209.846926)
		(width 0.18288)
		(layer "In4.Cu")
		(net "M_B_CPU0_SB_DQS_DN<3>")
	)
	(segment
		(start 323.783198 -218.047062)
		(end 323.850508 -217.884502)
		(width 0.18288)
		(layer "In4.Cu")
		(net "M_B_CPU0_SB_DQS_DN<3>")
	)
	(segment
		(start 322.2371 -214.315548)
		(end 322.30441 -214.152988)
		(width 0.18288)
		(layer "In4.Cu")
		(net "M_B_CPU0_SB_DQS_DN<3>")
	)
	(segment
		(start 330.731622 -223.13646)
		(end 330.671932 -223.07677)
		(width 0.088646)
		(layer "In4.Cu")
		(net "M_B_CPU0_SB_DQS_DN<3>")
	)
	(segment
		(start 313.601862 -201.262234)
		(end 313.180476 -200.840848)
		(width 0.18288)
		(layer "In4.Cu")
		(net "M_B_CPU0_SB_DQS_DN<3>")
	)
	(segment
		(start 330.648564 -223.07677)
		(end 328.515726 -223.07677)
		(width 0.18288)
		(layer "In4.Cu")
		(net "M_B_CPU0_SB_DQS_DN<3>")
	)
	(segment
		(start 323.64045 -217.377264)
		(end 323.477636 -217.309954)
		(width 0.18288)
		(layer "In4.Cu")
		(net "M_B_CPU0_SB_DQS_DN<3>")
	)
	(segment
		(start 299.21708 -200.2917)
		(end 298.78147 -200.2917)
		(width 0.18288)
		(layer "In4.Cu")
		(net "M_B_CPU0_SB_DQS_DN<3>")
	)
	(segment
		(start 312.616342 -200.276714)
		(end 312.105802 -199.766174)
		(width 0.18288)
		(layer "In4.Cu")
		(net "M_B_CPU0_SB_DQS_DN<3>")
	)
	(segment
		(start 303.239424 -200.443846)
		(end 302.63338 -200.564496)
		(width 0.18288)
		(layer "In4.Cu")
		(net "M_B_CPU0_SB_DQS_DN<3>")
	)
	(segment
		(start 321.063874 -211.158074)
		(end 320.900806 -211.090764)
		(width 0.18288)
		(layer "In4.Cu")
		(net "M_B_CPU0_SB_DQS_DN<3>")
	)
	(segment
		(start 321.931538 -213.57844)
		(end 321.721734 -213.07171)
		(width 0.18288)
		(layer "In4.Cu")
		(net "M_B_CPU0_SB_DQS_DN<3>")
	)
	(segment
		(start 322.96227 -216.066116)
		(end 322.752466 -215.559386)
		(width 0.18288)
		(layer "In4.Cu")
		(net "M_B_CPU0_SB_DQS_DN<3>")
	)
	(segment
		(start 298.172124 -200.556622)
		(end 297.54957 -199.934068)
		(width 0.18288)
		(layer "In4.Cu")
		(net "M_B_CPU0_SB_DQS_DN<3>")
	)
	(segment
		(start 319.212976 -206.68996)
		(end 319.003172 -206.182722)
		(width 0.18288)
		(layer "In4.Cu")
		(net "M_B_CPU0_SB_DQS_DN<3>")
	)
	(segment
		(start 320.033396 -208.670398)
		(end 319.870582 -208.603088)
		(width 0.18288)
		(layer "In4.Cu")
		(net "M_B_CPU0_SB_DQS_DN<3>")
	)
	(segment
		(start 320.691002 -210.584034)
		(end 320.758312 -210.421474)
		(width 0.18288)
		(layer "In4.Cu")
		(net "M_B_CPU0_SB_DQS_DN<3>")
	)
	(segment
		(start 328.515726 -223.07677)
		(end 323.993002 -218.553792)
		(width 0.18288)
		(layer "In4.Cu")
		(net "M_B_CPU0_SB_DQS_DN<3>")
	)
	(segment
		(start 319.145666 -206.85252)
		(end 319.212976 -206.68996)
		(width 0.18288)
		(layer "In4.Cu")
		(net "M_B_CPU0_SB_DQS_DN<3>")
	)
	(segment
		(start 323.335142 -216.640664)
		(end 323.125084 -216.133426)
		(width 0.18288)
		(layer "In4.Cu")
		(net "M_B_CPU0_SB_DQS_DN<3>")
	)
	(segment
		(start 330.671932 -223.07677)
		(end 330.648564 -223.07677)
		(width 0.088646)
		(layer "In4.Cu")
		(net "M_B_CPU0_SB_DQS_DN<3>")
	)
	(segment
		(start 321.273678 -211.665312)
		(end 321.063874 -211.158074)
		(width 0.18288)
		(layer "In4.Cu")
		(net "M_B_CPU0_SB_DQS_DN<3>")
	)
	(segment
		(start 323.477636 -217.309954)
		(end 323.267832 -216.803224)
		(width 0.18288)
		(layer "In4.Cu")
		(net "M_B_CPU0_SB_DQS_DN<3>")
	)
	(segment
		(start 298.78147 -200.2917)
		(end 298.516548 -200.556622)
		(width 0.18288)
		(layer "In4.Cu")
		(net "M_B_CPU0_SB_DQS_DN<3>")
	)
	(segment
		(start 321.721734 -213.07171)
		(end 321.789044 -212.90915)
		(width 0.18288)
		(layer "In4.Cu")
		(net "M_B_CPU0_SB_DQS_DN<3>")
	)
	(segment
		(start 313.180476 -200.840848)
		(end 313.180476 -200.664826)
		(width 0.18288)
		(layer "In4.Cu")
		(net "M_B_CPU0_SB_DQS_DN<3>")
	)
	(segment
		(start 321.206368 -211.827872)
		(end 321.273678 -211.665312)
		(width 0.18288)
		(layer "In4.Cu")
		(net "M_B_CPU0_SB_DQS_DN<3>")
	)
	(segment
		(start 331.5208 -224.018856)
		(end 331.5208 -223.470724)
		(width 0.088646)
		(layer "In4.Cu")
		(net "M_B_CPU0_SB_DQS_DN<3>")
	)
	(segment
		(start 322.752466 -215.559386)
		(end 322.819776 -215.396826)
		(width 0.18288)
		(layer "In4.Cu")
		(net "M_B_CPU0_SB_DQS_DN<3>")
	)
	(segment
		(start 331.5208 -223.470724)
		(end 331.186536 -223.13646)
		(width 0.088646)
		(layer "In4.Cu")
		(net "M_B_CPU0_SB_DQS_DN<3>")
	)
	(segment
		(start 321.57924 -212.401912)
		(end 321.416172 -212.334602)
		(width 0.18288)
		(layer "In4.Cu")
		(net "M_B_CPU0_SB_DQS_DN<3>")
	)
	(segment
		(start 319.870582 -208.603088)
		(end 319.660778 -208.096358)
		(width 0.18288)
		(layer "In4.Cu")
		(net "M_B_CPU0_SB_DQS_DN<3>")
	)
	(segment
		(start 322.30441 -214.152988)
		(end 322.094352 -213.64575)
		(width 0.18288)
		(layer "In4.Cu")
		(net "M_B_CPU0_SB_DQS_DN<3>")
	)
	(segment
		(start 320.900806 -211.090764)
		(end 320.691002 -210.584034)
		(width 0.18288)
		(layer "In4.Cu")
		(net "M_B_CPU0_SB_DQS_DN<3>")
	)
	(segment
		(start 312.792364 -200.276714)
		(end 312.616342 -200.276714)
		(width 0.18288)
		(layer "In4.Cu")
		(net "M_B_CPU0_SB_DQS_DN<3>")
	)
	(segment
		(start 320.2432 -209.177636)
		(end 320.033396 -208.670398)
		(width 0.18288)
		(layer "In4.Cu")
		(net "M_B_CPU0_SB_DQS_DN<3>")
	)
	(segment
		(start 313.180476 -200.664826)
		(end 312.792364 -200.276714)
		(width 0.18288)
		(layer "In4.Cu")
		(net "M_B_CPU0_SB_DQS_DN<3>")
	)
	(segment
		(start 319.660778 -208.096358)
		(end 319.728088 -207.933798)
		(width 0.18288)
		(layer "In4.Cu")
		(net "M_B_CPU0_SB_DQS_DN<3>")
	)
	(segment
		(start 331.186536 -223.13646)
		(end 330.731622 -223.13646)
		(width 0.088646)
		(layer "In4.Cu")
		(net "M_B_CPU0_SB_DQS_DN<3>")
	)
	(segment
		(start 314.567824 -201.262234)
		(end 313.601862 -201.262234)
		(width 0.18288)
		(layer "In4.Cu")
		(net "M_B_CPU0_SB_DQS_DN<3>")
	)
	(segment
		(start 321.416172 -212.334602)
		(end 321.206368 -211.827872)
		(width 0.18288)
		(layer "In4.Cu")
		(net "M_B_CPU0_SB_DQS_DN<3>")
	)
	(segment
		(start 319.518284 -207.42656)
		(end 319.35547 -207.35925)
		(width 0.18288)
		(layer "In4.Cu")
		(net "M_B_CPU0_SB_DQS_DN<3>")
	)
	(segment
		(start 318.840358 -206.115412)
		(end 318.42964 -205.123796)
		(width 0.18288)
		(layer "In4.Cu")
		(net "M_B_CPU0_SB_DQS_DN<3>")
	)
	(segment
		(start 319.003172 -206.182722)
		(end 318.840358 -206.115412)
		(width 0.18288)
		(layer "In4.Cu")
		(net "M_B_CPU0_SB_DQS_DN<3>")
	)
	(segment
		(start 298.516548 -200.556622)
		(end 298.172124 -200.556622)
		(width 0.18288)
		(layer "In4.Cu")
		(net "M_B_CPU0_SB_DQS_DN<3>")
	)
	(segment
		(start 323.125084 -216.133426)
		(end 322.96227 -216.066116)
		(width 0.18288)
		(layer "In4.Cu")
		(net "M_B_CPU0_SB_DQS_DN<3>")
	)
	(segment
		(start 319.728088 -207.933798)
		(end 319.518284 -207.42656)
		(width 0.18288)
		(layer "In4.Cu")
		(net "M_B_CPU0_SB_DQS_DN<3>")
	)
	(segment
		(start 299.489876 -200.564496)
		(end 299.21708 -200.2917)
		(width 0.18288)
		(layer "In4.Cu")
		(net "M_B_CPU0_SB_DQS_DN<3>")
	)
	(segment
		(start 321.789044 -212.90915)
		(end 321.57924 -212.401912)
		(width 0.18288)
		(layer "In4.Cu")
		(net "M_B_CPU0_SB_DQS_DN<3>")
	)
	(segment
		(start 332.321408 -224.819464)
		(end 331.5208 -224.018856)
		(width 0.088646)
		(layer "In4.Cu")
		(net "M_B_CPU0_SB_DQS_DN<3>")
	)
	(segment
		(start 320.17589 -209.340196)
		(end 320.2432 -209.177636)
		(width 0.18288)
		(layer "In4.Cu")
		(net "M_B_CPU0_SB_DQS_DN<3>")
	)
	(segment
		(start 302.63338 -200.564496)
		(end 299.489876 -200.564496)
		(width 0.18288)
		(layer "In4.Cu")
		(net "M_B_CPU0_SB_DQS_DN<3>")
	)
	(segment
		(start 295.61663 -200.12533)
		(end 295.162986 -200.12533)
		(width 0.18288)
		(layer "In4.Cu")
		(net "M_B_CPU0_SB_DQS_DN<3>")
	)
	(segment
		(start 296.078656 -199.934068)
		(end 295.61663 -200.12533)
		(width 0.18288)
		(layer "In4.Cu")
		(net "M_B_CPU0_SB_DQS_DN<3>")
	)
	(segment
		(start 297.54957 -199.934068)
		(end 296.078656 -199.934068)
		(width 0.18288)
		(layer "In4.Cu")
		(net "M_B_CPU0_SB_DQS_DN<3>")
	)
	(segment
		(start 323.850508 -217.884502)
		(end 323.64045 -217.377264)
		(width 0.18288)
		(layer "In4.Cu")
		(net "M_B_CPU0_SB_DQS_DN<3>")
	)
	(segment
		(start 318.42964 -205.123796)
		(end 314.567824 -201.262234)
		(width 0.18288)
		(layer "In4.Cu")
		(net "M_B_CPU0_SB_DQS_DN<3>")
	)
	(segment
		(start 322.819776 -215.396826)
		(end 322.609718 -214.889588)
		(width 0.18288)
		(layer "In4.Cu")
		(net "M_B_CPU0_SB_DQS_DN<3>")
	)
	(segment
		(start 320.758312 -210.421474)
		(end 320.548508 -209.914236)
		(width 0.18288)
		(layer "In4.Cu")
		(net "M_B_CPU0_SB_DQS_DN<3>")
	)
	(segment
		(start 323.267832 -216.803224)
		(end 323.335142 -216.640664)
		(width 0.18288)
		(layer "In4.Cu")
		(net "M_B_CPU0_SB_DQS_DN<3>")
	)
	(segment
		(start 320.385694 -209.846926)
		(end 320.17589 -209.340196)
		(width 0.18288)
		(layer "In4.Cu")
		(net "M_B_CPU0_SB_DQS_DN<3>")
	)
	(segment
		(start 323.993002 -218.553792)
		(end 323.783198 -218.047062)
		(width 0.18288)
		(layer "In4.Cu")
		(net "M_B_CPU0_SB_DQS_DN<3>")
	)
	(arc
		(start 332.791308 -225.195384)
		(mid 332.683324 -225.054925)
		(end 332.542642 -224.947226)
		(width 0.088646)
		(layer "In4.Cu")
		(net "M_B_CPU0_SB_DQS_DN<3>")
	)
	(segment
		(start 289.23234 -209.631026)
		(end 289.231578 -209.631026)
		(width 0.101854)
		(layer "F.Cu")
		(net "M_B_CPU0_SB_DQS_DN<2>")
	)
	(segment
		(start 292.58514 -209.477864)
		(end 292.159944 -209.90306)
		(width 0.20066)
		(layer "F.Cu")
		(net "M_B_CPU0_SB_DQS_DN<2>")
	)
	(segment
		(start 286.804354 -209.216752)
		(end 286.255714 -209.216752)
		(width 0.20066)
		(layer "F.Cu")
		(net "M_B_CPU0_SB_DQS_DN<2>")
	)
	(segment
		(start 294.904414 -209.216752)
		(end 293.799514 -209.216752)
		(width 0.20066)
		(layer "F.Cu")
		(net "M_B_CPU0_SB_DQS_DN<2>")
	)
	(segment
		(start 288.215324 -209.90306)
		(end 287.579308 -209.477864)
		(width 0.20066)
		(layer "F.Cu")
		(net "M_B_CPU0_SB_DQS_DN<2>")
	)
	(segment
		(start 289.243008 -209.641694)
		(end 289.23234 -209.631026)
		(width 0.101854)
		(layer "F.Cu")
		(net "M_B_CPU0_SB_DQS_DN<2>")
	)
	(segment
		(start 289.231578 -209.631026)
		(end 289.027362 -209.631026)
		(width 0.20066)
		(layer "F.Cu")
		(net "M_B_CPU0_SB_DQS_DN<2>")
	)
	(segment
		(start 292.159944 -209.90306)
		(end 291.973254 -209.90306)
		(width 0.20066)
		(layer "F.Cu")
		(net "M_B_CPU0_SB_DQS_DN<2>")
	)
	(segment
		(start 293.799514 -209.216752)
		(end 293.252906 -209.216752)
		(width 0.20066)
		(layer "F.Cu")
		(net "M_B_CPU0_SB_DQS_DN<2>")
	)
	(segment
		(start 292.991794 -209.477864)
		(end 292.58514 -209.477864)
		(width 0.20066)
		(layer "F.Cu")
		(net "M_B_CPU0_SB_DQS_DN<2>")
	)
	(segment
		(start 288.755328 -209.90306)
		(end 288.215324 -209.90306)
		(width 0.20066)
		(layer "F.Cu")
		(net "M_B_CPU0_SB_DQS_DN<2>")
	)
	(segment
		(start 287.579308 -209.477864)
		(end 287.065466 -209.477864)
		(width 0.20066)
		(layer "F.Cu")
		(net "M_B_CPU0_SB_DQS_DN<2>")
	)
	(segment
		(start 289.027362 -209.631026)
		(end 288.755328 -209.90306)
		(width 0.20066)
		(layer "F.Cu")
		(net "M_B_CPU0_SB_DQS_DN<2>")
	)
	(segment
		(start 287.065466 -209.477864)
		(end 286.804354 -209.216752)
		(width 0.20066)
		(layer "F.Cu")
		(net "M_B_CPU0_SB_DQS_DN<2>")
	)
	(segment
		(start 336.085434 -228.1809)
		(end 336.085434 -227.64496)
		(width 0.20066)
		(layer "F.Cu")
		(net "M_B_CPU0_SB_DQS_DN<2>")
	)
	(segment
		(start 293.252906 -209.216752)
		(end 292.991794 -209.477864)
		(width 0.20066)
		(layer "F.Cu")
		(net "M_B_CPU0_SB_DQS_DN<2>")
	)
	(segment
		(start 291.556694 -209.641694)
		(end 289.243008 -209.641694)
		(width 0.1016)
		(layer "F.Cu")
		(net "M_B_CPU0_SB_DQS_DN<2>")
	)
	(segment
		(start 291.711888 -209.641694)
		(end 291.556694 -209.641694)
		(width 0.20066)
		(layer "F.Cu")
		(net "M_B_CPU0_SB_DQS_DN<2>")
	)
	(segment
		(start 291.973254 -209.90306)
		(end 291.711888 -209.641694)
		(width 0.20066)
		(layer "F.Cu")
		(net "M_B_CPU0_SB_DQS_DN<2>")
	)
	(segment
		(start 331.943964 -223.077278)
		(end 331.788008 -223.077278)
		(width 0.18288)
		(layer "In2.Cu")
		(net "M_B_CPU0_SB_DQS_DN<2>")
	)
	(segment
		(start 316.170818 -209.170778)
		(end 315.622178 -209.170778)
		(width 0.18288)
		(layer "In2.Cu")
		(net "M_B_CPU0_SB_DQS_DN<2>")
	)
	(segment
		(start 313.956954 -209.361024)
		(end 313.956954 -209.37728)
		(width 0.16002)
		(layer "In2.Cu")
		(net "M_B_CPU0_SB_DQS_DN<2>")
	)
	(segment
		(start 309.860188 -208.653126)
		(end 309.860188 -208.637378)
		(width 0.16002)
		(layer "In2.Cu")
		(net "M_B_CPU0_SB_DQS_DN<2>")
	)
	(segment
		(start 333.548736 -223.899984)
		(end 333.539846 -223.894904)
		(width 0.088646)
		(layer "In2.Cu")
		(net "M_B_CPU0_SB_DQS_DN<2>")
	)
	(segment
		(start 309.64886 -208.42605)
		(end 308.125368 -208.42605)
		(width 0.18288)
		(layer "In2.Cu")
		(net "M_B_CPU0_SB_DQS_DN<2>")
	)
	(segment
		(start 297.298364 -209.744818)
		(end 297.27017 -209.716624)
		(width 0.16002)
		(layer "In2.Cu")
		(net "M_B_CPU0_SB_DQS_DN<2>")
	)
	(segment
		(start 306.076604 -209.697574)
		(end 304.81016 -209.697574)
		(width 0.18288)
		(layer "In2.Cu")
		(net "M_B_CPU0_SB_DQS_DN<2>")
	)
	(segment
		(start 334.301084 -225.203258)
		(end 334.301084 -225.193352)
		(width 0.088646)
		(layer "In2.Cu")
		(net "M_B_CPU0_SB_DQS_DN<2>")
	)
	(segment
		(start 307.69814 -208.853278)
		(end 307.669946 -208.881472)
		(width 0.16002)
		(layer "In2.Cu")
		(net "M_B_CPU0_SB_DQS_DN<2>")
	)
	(segment
		(start 306.21351 -209.576924)
		(end 306.197254 -209.576924)
		(width 0.16002)
		(layer "In2.Cu")
		(net "M_B_CPU0_SB_DQS_DN<2>")
	)
	(segment
		(start 313.985148 -209.33283)
		(end 313.956954 -209.361024)
		(width 0.16002)
		(layer "In2.Cu")
		(net "M_B_CPU0_SB_DQS_DN<2>")
	)
	(segment
		(start 319.922652 -211.0359)
		(end 319.53454 -210.647788)
		(width 0.18288)
		(layer "In2.Cu")
		(net "M_B_CPU0_SB_DQS_DN<2>")
	)
	(segment
		(start 302.34128 -210.182714)
		(end 302.313086 -210.210908)
		(width 0.16002)
		(layer "In2.Cu")
		(net "M_B_CPU0_SB_DQS_DN<2>")
	)
	(segment
		(start 296.784776 -209.23123)
		(end 296.140378 -209.23123)
		(width 0.18288)
		(layer "In2.Cu")
		(net "M_B_CPU0_SB_DQS_DN<2>")
	)
	(segment
		(start 335.897474 -227.42652)
		(end 335.428082 -227.155502)
		(width 0.088646)
		(layer "In2.Cu")
		(net "M_B_CPU0_SB_DQS_DN<2>")
	)
	(segment
		(start 321.262502 -212.551772)
		(end 320.874644 -212.163914)
		(width 0.18288)
		(layer "In2.Cu")
		(net "M_B_CPU0_SB_DQS_DN<2>")
	)
	(segment
		(start 322.778628 -214.067898)
		(end 322.778628 -213.891876)
		(width 0.18288)
		(layer "In2.Cu")
		(net "M_B_CPU0_SB_DQS_DN<2>")
	)
	(segment
		(start 300.573186 -210.426808)
		(end 300.373542 -210.227164)
		(width 0.16002)
		(layer "In2.Cu")
		(net "M_B_CPU0_SB_DQS_DN<2>")
	)
	(segment
		(start 333.078582 -223.085914)
		(end 333.06385 -223.077278)
		(width 0.088646)
		(layer "In2.Cu")
		(net "M_B_CPU0_SB_DQS_DN<2>")
	)
	(segment
		(start 310.313578 -209.090768)
		(end 310.104282 -208.881472)
		(width 0.18288)
		(layer "In2.Cu")
		(net "M_B_CPU0_SB_DQS_DN<2>")
	)
	(segment
		(start 306.16906 -209.605118)
		(end 306.076604 -209.697574)
		(width 0.18288)
		(layer "In2.Cu")
		(net "M_B_CPU0_SB_DQS_DN<2>")
	)
	(segment
		(start 323.73062 -215.01989)
		(end 323.73062 -214.843868)
		(width 0.18288)
		(layer "In2.Cu")
		(net "M_B_CPU0_SB_DQS_DN<2>")
	)
	(segment
		(start 323.73062 -214.843868)
		(end 323.342508 -214.455756)
		(width 0.18288)
		(layer "In2.Cu")
		(net "M_B_CPU0_SB_DQS_DN<2>")
	)
	(segment
		(start 297.05427 -209.51698)
		(end 297.05427 -209.500724)
		(width 0.16002)
		(layer "In2.Cu")
		(net "M_B_CPU0_SB_DQS_DN<2>")
	)
	(segment
		(start 307.91404 -208.637378)
		(end 307.91404 -208.653126)
		(width 0.16002)
		(layer "In2.Cu")
		(net "M_B_CPU0_SB_DQS_DN<2>")
	)
	(segment
		(start 334.017874 -224.713292)
		(end 334.015334 -224.711768)
		(width 0.088646)
		(layer "In2.Cu")
		(net "M_B_CPU0_SB_DQS_DN<2>")
	)
	(segment
		(start 299.186854 -209.641694)
		(end 298.810172 -209.641694)
		(width 0.18288)
		(layer "In2.Cu")
		(net "M_B_CPU0_SB_DQS_DN<2>")
	)
	(segment
		(start 312.01741 -209.361024)
		(end 311.989216 -209.33283)
		(width 0.16002)
		(layer "In2.Cu")
		(net "M_B_CPU0_SB_DQS_DN<2>")
	)
	(segment
		(start 320.31051 -211.59978)
		(end 319.922652 -211.211922)
		(width 0.18288)
		(layer "In2.Cu")
		(net "M_B_CPU0_SB_DQS_DN<2>")
	)
	(segment
		(start 296.140378 -209.23123)
		(end 295.523158 -209.486754)
		(width 0.18288)
		(layer "In2.Cu")
		(net "M_B_CPU0_SB_DQS_DN<2>")
	)
	(segment
		(start 336.085434 -227.64496)
		(end 336.05851 -227.582984)
		(width 0.088646)
		(layer "In2.Cu")
		(net "M_B_CPU0_SB_DQS_DN<2>")
	)
	(segment
		(start 309.831994 -208.609184)
		(end 309.64886 -208.42605)
		(width 0.18288)
		(layer "In2.Cu")
		(net "M_B_CPU0_SB_DQS_DN<2>")
	)
	(segment
		(start 310.104282 -208.881472)
		(end 310.076088 -208.853278)
		(width 0.16002)
		(layer "In2.Cu")
		(net "M_B_CPU0_SB_DQS_DN<2>")
	)
	(segment
		(start 307.713888 -208.853278)
		(end 307.69814 -208.853278)
		(width 0.16002)
		(layer "In2.Cu")
		(net "M_B_CPU0_SB_DQS_DN<2>")
	)
	(segment
		(start 304.717704 -209.605118)
		(end 304.68951 -209.576924)
		(width 0.16002)
		(layer "In2.Cu")
		(net "M_B_CPU0_SB_DQS_DN<2>")
	)
	(segment
		(start 336.05851 -227.582984)
		(end 335.897474 -227.42652)
		(width 0.088646)
		(layer "In2.Cu")
		(net "M_B_CPU0_SB_DQS_DN<2>")
	)
	(segment
		(start 332.003654 -223.136968)
		(end 331.943964 -223.077278)
		(width 0.088646)
		(layer "In2.Cu")
		(net "M_B_CPU0_SB_DQS_DN<2>")
	)
	(segment
		(start 318.005968 -209.295238)
		(end 317.641478 -209.295238)
		(width 0.18288)
		(layer "In2.Cu")
		(net "M_B_CPU0_SB_DQS_DN<2>")
	)
	(segment
		(start 300.345348 -210.182714)
		(end 300.071536 -209.908902)
		(width 0.18288)
		(layer "In2.Cu")
		(net "M_B_CPU0_SB_DQS_DN<2>")
	)
	(segment
		(start 318.582548 -209.695796)
		(end 318.406526 -209.695796)
		(width 0.18288)
		(layer "In2.Cu")
		(net "M_B_CPU0_SB_DQS_DN<2>")
	)
	(segment
		(start 308.125368 -208.42605)
		(end 307.942234 -208.609184)
		(width 0.18288)
		(layer "In2.Cu")
		(net "M_B_CPU0_SB_DQS_DN<2>")
	)
	(segment
		(start 325.246492 -216.35974)
		(end 325.07047 -216.35974)
		(width 0.18288)
		(layer "In2.Cu")
		(net "M_B_CPU0_SB_DQS_DN<2>")
	)
	(segment
		(start 297.27017 -209.716624)
		(end 297.253914 -209.716624)
		(width 0.16002)
		(layer "In2.Cu")
		(net "M_B_CPU0_SB_DQS_DN<2>")
	)
	(segment
		(start 322.214494 -213.503764)
		(end 321.826636 -213.115906)
		(width 0.18288)
		(layer "In2.Cu")
		(net "M_B_CPU0_SB_DQS_DN<2>")
	)
	(segment
		(start 302.113442 -210.426808)
		(end 302.097186 -210.426808)
		(width 0.16002)
		(layer "In2.Cu")
		(net "M_B_CPU0_SB_DQS_DN<2>")
	)
	(segment
		(start 323.166486 -214.455756)
		(end 322.778628 -214.067898)
		(width 0.18288)
		(layer "In2.Cu")
		(net "M_B_CPU0_SB_DQS_DN<2>")
	)
	(segment
		(start 306.748688 -209.02549)
		(end 306.441348 -209.33283)
		(width 0.18288)
		(layer "In2.Cu")
		(net "M_B_CPU0_SB_DQS_DN<2>")
	)
	(segment
		(start 316.968378 -209.170778)
		(end 316.843918 -209.295238)
		(width 0.18288)
		(layer "In2.Cu")
		(net "M_B_CPU0_SB_DQS_DN<2>")
	)
	(segment
		(start 326.586596 -217.875866)
		(end 326.586596 -217.699844)
		(width 0.18288)
		(layer "In2.Cu")
		(net "M_B_CPU0_SB_DQS_DN<2>")
	)
	(segment
		(start 326.974454 -218.263724)
		(end 326.586596 -217.875866)
		(width 0.18288)
		(layer "In2.Cu")
		(net "M_B_CPU0_SB_DQS_DN<2>")
	)
	(segment
		(start 312.35396 -209.697574)
		(end 312.261504 -209.605118)
		(width 0.18288)
		(layer "In2.Cu")
		(net "M_B_CPU0_SB_DQS_DN<2>")
	)
	(segment
		(start 304.47361 -209.361024)
		(end 304.445416 -209.33283)
		(width 0.16002)
		(layer "In2.Cu")
		(net "M_B_CPU0_SB_DQS_DN<2>")
	)
	(segment
		(start 326.586596 -217.699844)
		(end 326.198484 -217.311732)
		(width 0.18288)
		(layer "In2.Cu")
		(net "M_B_CPU0_SB_DQS_DN<2>")
	)
	(segment
		(start 316.843918 -209.295238)
		(end 316.295278 -209.295238)
		(width 0.18288)
		(layer "In2.Cu")
		(net "M_B_CPU0_SB_DQS_DN<2>")
	)
	(segment
		(start 322.390516 -213.503764)
		(end 322.214494 -213.503764)
		(width 0.18288)
		(layer "In2.Cu")
		(net "M_B_CPU0_SB_DQS_DN<2>")
	)
	(segment
		(start 304.168556 -209.05597)
		(end 303.468024 -209.05597)
		(width 0.18288)
		(layer "In2.Cu")
		(net "M_B_CPU0_SB_DQS_DN<2>")
	)
	(segment
		(start 309.860188 -208.637378)
		(end 309.831994 -208.609184)
		(width 0.16002)
		(layer "In2.Cu")
		(net "M_B_CPU0_SB_DQS_DN<2>")
	)
	(segment
		(start 332.513178 -223.085914)
		(end 332.513432 -223.086676)
		(width 0.088646)
		(layer "In2.Cu")
		(net "M_B_CPU0_SB_DQS_DN<2>")
	)
	(segment
		(start 304.445416 -209.33283)
		(end 304.168556 -209.05597)
		(width 0.18288)
		(layer "In2.Cu")
		(net "M_B_CPU0_SB_DQS_DN<2>")
	)
	(segment
		(start 314.874656 -209.295238)
		(end 314.715652 -209.136234)
		(width 0.18288)
		(layer "In2.Cu")
		(net "M_B_CPU0_SB_DQS_DN<2>")
	)
	(segment
		(start 306.197254 -209.576924)
		(end 306.16906 -209.605118)
		(width 0.16002)
		(layer "In2.Cu")
		(net "M_B_CPU0_SB_DQS_DN<2>")
	)
	(segment
		(start 320.486532 -211.59978)
		(end 320.31051 -211.59978)
		(width 0.18288)
		(layer "In2.Cu")
		(net "M_B_CPU0_SB_DQS_DN<2>")
	)
	(segment
		(start 300.373542 -210.227164)
		(end 300.373542 -210.210908)
		(width 0.16002)
		(layer "In2.Cu")
		(net "M_B_CPU0_SB_DQS_DN<2>")
	)
	(segment
		(start 319.922652 -211.211922)
		(end 319.922652 -211.0359)
		(width 0.18288)
		(layer "In2.Cu")
		(net "M_B_CPU0_SB_DQS_DN<2>")
	)
	(segment
		(start 298.52747 -209.924396)
		(end 297.477942 -209.924396)
		(width 0.18288)
		(layer "In2.Cu")
		(net "M_B_CPU0_SB_DQS_DN<2>")
	)
	(segment
		(start 307.942234 -208.609184)
		(end 307.91404 -208.637378)
		(width 0.16002)
		(layer "In2.Cu")
		(net "M_B_CPU0_SB_DQS_DN<2>")
	)
	(segment
		(start 297.05427 -209.500724)
		(end 297.026076 -209.47253)
		(width 0.16002)
		(layer "In2.Cu")
		(net "M_B_CPU0_SB_DQS_DN<2>")
	)
	(segment
		(start 314.715652 -209.136234)
		(end 314.181744 -209.136234)
		(width 0.18288)
		(layer "In2.Cu")
		(net "M_B_CPU0_SB_DQS_DN<2>")
	)
	(segment
		(start 321.438524 -212.551772)
		(end 321.262502 -212.551772)
		(width 0.18288)
		(layer "In2.Cu")
		(net "M_B_CPU0_SB_DQS_DN<2>")
	)
	(segment
		(start 327.538588 -218.651836)
		(end 327.150476 -218.263724)
		(width 0.18288)
		(layer "In2.Cu")
		(net "M_B_CPU0_SB_DQS_DN<2>")
	)
	(segment
		(start 297.477942 -209.924396)
		(end 297.298364 -209.744818)
		(width 0.18288)
		(layer "In2.Cu")
		(net "M_B_CPU0_SB_DQS_DN<2>")
	)
	(segment
		(start 312.23331 -209.576924)
		(end 312.217054 -209.576924)
		(width 0.16002)
		(layer "In2.Cu")
		(net "M_B_CPU0_SB_DQS_DN<2>")
	)
	(segment
		(start 307.91404 -208.653126)
		(end 307.713888 -208.853278)
		(width 0.16002)
		(layer "In2.Cu")
		(net "M_B_CPU0_SB_DQS_DN<2>")
	)
	(segment
		(start 304.68951 -209.576924)
		(end 304.673254 -209.576924)
		(width 0.16002)
		(layer "In2.Cu")
		(net "M_B_CPU0_SB_DQS_DN<2>")
	)
	(segment
		(start 300.710092 -210.547458)
		(end 300.617636 -210.455002)
		(width 0.18288)
		(layer "In2.Cu")
		(net "M_B_CPU0_SB_DQS_DN<2>")
	)
	(segment
		(start 313.75731 -209.576924)
		(end 313.741054 -209.576924)
		(width 0.16002)
		(layer "In2.Cu")
		(net "M_B_CPU0_SB_DQS_DN<2>")
	)
	(segment
		(start 313.741054 -209.576924)
		(end 313.71286 -209.605118)
		(width 0.16002)
		(layer "In2.Cu")
		(net "M_B_CPU0_SB_DQS_DN<2>")
	)
	(segment
		(start 311.747154 -209.090768)
		(end 310.313578 -209.090768)
		(width 0.18288)
		(layer "In2.Cu")
		(net "M_B_CPU0_SB_DQS_DN<2>")
	)
	(segment
		(start 306.413154 -209.361024)
		(end 306.413154 -209.37728)
		(width 0.16002)
		(layer "In2.Cu")
		(net "M_B_CPU0_SB_DQS_DN<2>")
	)
	(segment
		(start 312.217054 -209.576924)
		(end 312.01741 -209.37728)
		(width 0.16002)
		(layer "In2.Cu")
		(net "M_B_CPU0_SB_DQS_DN<2>")
	)
	(segment
		(start 304.673254 -209.576924)
		(end 304.47361 -209.37728)
		(width 0.16002)
		(layer "In2.Cu")
		(net "M_B_CPU0_SB_DQS_DN<2>")
	)
	(segment
		(start 334.970374 -226.348798)
		(end 334.958182 -226.341686)
		(width 0.088646)
		(layer "In2.Cu")
		(net "M_B_CPU0_SB_DQS_DN<2>")
	)
	(segment
		(start 320.874644 -212.163914)
		(end 320.874644 -211.987892)
		(width 0.18288)
		(layer "In2.Cu")
		(net "M_B_CPU0_SB_DQS_DN<2>")
	)
	(segment
		(start 297.026076 -209.47253)
		(end 296.784776 -209.23123)
		(width 0.18288)
		(layer "In2.Cu")
		(net "M_B_CPU0_SB_DQS_DN<2>")
	)
	(segment
		(start 306.413154 -209.37728)
		(end 306.21351 -209.576924)
		(width 0.16002)
		(layer "In2.Cu")
		(net "M_B_CPU0_SB_DQS_DN<2>")
	)
	(segment
		(start 324.118478 -215.407748)
		(end 323.73062 -215.01989)
		(width 0.18288)
		(layer "In2.Cu")
		(net "M_B_CPU0_SB_DQS_DN<2>")
	)
	(segment
		(start 321.826636 -212.939884)
		(end 321.438524 -212.551772)
		(width 0.18288)
		(layer "In2.Cu")
		(net "M_B_CPU0_SB_DQS_DN<2>")
	)
	(segment
		(start 317.641478 -209.295238)
		(end 317.517018 -209.170778)
		(width 0.18288)
		(layer "In2.Cu")
		(net "M_B_CPU0_SB_DQS_DN<2>")
	)
	(segment
		(start 307.669946 -208.881472)
		(end 307.525928 -209.02549)
		(width 0.18288)
		(layer "In2.Cu")
		(net "M_B_CPU0_SB_DQS_DN<2>")
	)
	(segment
		(start 303.468024 -209.05597)
		(end 302.34128 -210.182714)
		(width 0.18288)
		(layer "In2.Cu")
		(net "M_B_CPU0_SB_DQS_DN<2>")
	)
	(segment
		(start 321.826636 -213.115906)
		(end 321.826636 -212.939884)
		(width 0.18288)
		(layer "In2.Cu")
		(net "M_B_CPU0_SB_DQS_DN<2>")
	)
	(segment
		(start 300.071536 -209.908902)
		(end 299.454062 -209.908902)
		(width 0.18288)
		(layer "In2.Cu")
		(net "M_B_CPU0_SB_DQS_DN<2>")
	)
	(segment
		(start 333.554832 -223.90354)
		(end 333.548736 -223.899984)
		(width 0.088646)
		(layer "In2.Cu")
		(net "M_B_CPU0_SB_DQS_DN<2>")
	)
	(segment
		(start 318.97066 -210.083908)
		(end 318.582548 -209.695796)
		(width 0.18288)
		(layer "In2.Cu")
		(net "M_B_CPU0_SB_DQS_DN<2>")
	)
	(segment
		(start 304.47361 -209.37728)
		(end 304.47361 -209.361024)
		(width 0.16002)
		(layer "In2.Cu")
		(net "M_B_CPU0_SB_DQS_DN<2>")
	)
	(segment
		(start 307.525928 -209.02549)
		(end 306.748688 -209.02549)
		(width 0.18288)
		(layer "In2.Cu")
		(net "M_B_CPU0_SB_DQS_DN<2>")
	)
	(segment
		(start 334.488536 -225.527616)
		(end 334.479646 -225.522536)
		(width 0.088646)
		(layer "In2.Cu")
		(net "M_B_CPU0_SB_DQS_DN<2>")
	)
	(segment
		(start 304.81016 -209.697574)
		(end 304.717704 -209.605118)
		(width 0.18288)
		(layer "In2.Cu")
		(net "M_B_CPU0_SB_DQS_DN<2>")
	)
	(segment
		(start 300.589442 -210.426808)
		(end 300.573186 -210.426808)
		(width 0.16002)
		(layer "In2.Cu")
		(net "M_B_CPU0_SB_DQS_DN<2>")
	)
	(segment
		(start 313.956954 -209.37728)
		(end 313.75731 -209.576924)
		(width 0.16002)
		(layer "In2.Cu")
		(net "M_B_CPU0_SB_DQS_DN<2>")
	)
	(segment
		(start 302.097186 -210.426808)
		(end 302.068992 -210.455002)
		(width 0.16002)
		(layer "In2.Cu")
		(net "M_B_CPU0_SB_DQS_DN<2>")
	)
	(segment
		(start 315.622178 -209.170778)
		(end 315.497718 -209.295238)
		(width 0.18288)
		(layer "In2.Cu")
		(net "M_B_CPU0_SB_DQS_DN<2>")
	)
	(segment
		(start 301.976536 -210.547458)
		(end 300.710092 -210.547458)
		(width 0.18288)
		(layer "In2.Cu")
		(net "M_B_CPU0_SB_DQS_DN<2>")
	)
	(segment
		(start 316.295278 -209.295238)
		(end 316.170818 -209.170778)
		(width 0.18288)
		(layer "In2.Cu")
		(net "M_B_CPU0_SB_DQS_DN<2>")
	)
	(segment
		(start 314.181744 -209.136234)
		(end 313.985148 -209.33283)
		(width 0.18288)
		(layer "In2.Cu")
		(net "M_B_CPU0_SB_DQS_DN<2>")
	)
	(segment
		(start 331.788008 -223.077278)
		(end 327.538588 -218.827858)
		(width 0.18288)
		(layer "In2.Cu")
		(net "M_B_CPU0_SB_DQS_DN<2>")
	)
	(segment
		(start 311.989216 -209.33283)
		(end 311.747154 -209.090768)
		(width 0.18288)
		(layer "In2.Cu")
		(net "M_B_CPU0_SB_DQS_DN<2>")
	)
	(segment
		(start 320.874644 -211.987892)
		(end 320.486532 -211.59978)
		(width 0.18288)
		(layer "In2.Cu")
		(net "M_B_CPU0_SB_DQS_DN<2>")
	)
	(segment
		(start 317.517018 -209.170778)
		(end 316.968378 -209.170778)
		(width 0.18288)
		(layer "In2.Cu")
		(net "M_B_CPU0_SB_DQS_DN<2>")
	)
	(segment
		(start 322.778628 -213.891876)
		(end 322.390516 -213.503764)
		(width 0.18288)
		(layer "In2.Cu")
		(net "M_B_CPU0_SB_DQS_DN<2>")
	)
	(segment
		(start 295.523158 -209.486754)
		(end 295.174416 -209.486754)
		(width 0.18288)
		(layer "In2.Cu")
		(net "M_B_CPU0_SB_DQS_DN<2>")
	)
	(segment
		(start 334.015334 -224.711768)
		(end 334.009746 -224.70872)
		(width 0.088646)
		(layer "In2.Cu")
		(net "M_B_CPU0_SB_DQS_DN<2>")
	)
	(segment
		(start 333.361284 -223.575626)
		(end 333.361284 -223.561402)
		(width 0.088646)
		(layer "In2.Cu")
		(net "M_B_CPU0_SB_DQS_DN<2>")
	)
	(segment
		(start 332.325726 -223.136968)
		(end 332.003654 -223.136968)
		(width 0.088646)
		(layer "In2.Cu")
		(net "M_B_CPU0_SB_DQS_DN<2>")
	)
	(segment
		(start 312.261504 -209.605118)
		(end 312.23331 -209.576924)
		(width 0.16002)
		(layer "In2.Cu")
		(net "M_B_CPU0_SB_DQS_DN<2>")
	)
	(segment
		(start 325.07047 -216.35974)
		(end 324.682612 -215.971882)
		(width 0.18288)
		(layer "In2.Cu")
		(net "M_B_CPU0_SB_DQS_DN<2>")
	)
	(segment
		(start 318.97066 -210.25993)
		(end 318.97066 -210.083908)
		(width 0.18288)
		(layer "In2.Cu")
		(net "M_B_CPU0_SB_DQS_DN<2>")
	)
	(segment
		(start 319.358518 -210.647788)
		(end 318.97066 -210.25993)
		(width 0.18288)
		(layer "In2.Cu")
		(net "M_B_CPU0_SB_DQS_DN<2>")
	)
	(segment
		(start 312.01741 -209.37728)
		(end 312.01741 -209.361024)
		(width 0.16002)
		(layer "In2.Cu")
		(net "M_B_CPU0_SB_DQS_DN<2>")
	)
	(segment
		(start 315.497718 -209.295238)
		(end 314.874656 -209.295238)
		(width 0.18288)
		(layer "In2.Cu")
		(net "M_B_CPU0_SB_DQS_DN<2>")
	)
	(segment
		(start 313.620404 -209.697574)
		(end 312.35396 -209.697574)
		(width 0.18288)
		(layer "In2.Cu")
		(net "M_B_CPU0_SB_DQS_DN<2>")
	)
	(segment
		(start 310.06034 -208.853278)
		(end 309.860188 -208.653126)
		(width 0.16002)
		(layer "In2.Cu")
		(net "M_B_CPU0_SB_DQS_DN<2>")
	)
	(segment
		(start 313.71286 -209.605118)
		(end 313.620404 -209.697574)
		(width 0.18288)
		(layer "In2.Cu")
		(net "M_B_CPU0_SB_DQS_DN<2>")
	)
	(segment
		(start 302.313086 -210.210908)
		(end 302.313086 -210.227164)
		(width 0.16002)
		(layer "In2.Cu")
		(net "M_B_CPU0_SB_DQS_DN<2>")
	)
	(segment
		(start 327.538588 -218.827858)
		(end 327.538588 -218.651836)
		(width 0.18288)
		(layer "In2.Cu")
		(net "M_B_CPU0_SB_DQS_DN<2>")
	)
	(segment
		(start 302.068992 -210.455002)
		(end 301.976536 -210.547458)
		(width 0.18288)
		(layer "In2.Cu")
		(net "M_B_CPU0_SB_DQS_DN<2>")
	)
	(segment
		(start 323.342508 -214.455756)
		(end 323.166486 -214.455756)
		(width 0.18288)
		(layer "In2.Cu")
		(net "M_B_CPU0_SB_DQS_DN<2>")
	)
	(segment
		(start 324.2945 -215.407748)
		(end 324.118478 -215.407748)
		(width 0.18288)
		(layer "In2.Cu")
		(net "M_B_CPU0_SB_DQS_DN<2>")
	)
	(segment
		(start 319.53454 -210.647788)
		(end 319.358518 -210.647788)
		(width 0.18288)
		(layer "In2.Cu")
		(net "M_B_CPU0_SB_DQS_DN<2>")
	)
	(segment
		(start 302.313086 -210.227164)
		(end 302.113442 -210.426808)
		(width 0.16002)
		(layer "In2.Cu")
		(net "M_B_CPU0_SB_DQS_DN<2>")
	)
	(segment
		(start 295.174416 -209.486754)
		(end 294.904414 -209.216752)
		(width 0.18288)
		(layer "In2.Cu")
		(net "M_B_CPU0_SB_DQS_DN<2>")
	)
	(segment
		(start 325.634604 -216.923874)
		(end 325.634604 -216.747852)
		(width 0.18288)
		(layer "In2.Cu")
		(net "M_B_CPU0_SB_DQS_DN<2>")
	)
	(segment
		(start 299.454062 -209.908902)
		(end 299.186854 -209.641694)
		(width 0.18288)
		(layer "In2.Cu")
		(net "M_B_CPU0_SB_DQS_DN<2>")
	)
	(segment
		(start 326.022462 -217.311732)
		(end 325.634604 -216.923874)
		(width 0.18288)
		(layer "In2.Cu")
		(net "M_B_CPU0_SB_DQS_DN<2>")
	)
	(segment
		(start 325.634604 -216.747852)
		(end 325.246492 -216.35974)
		(width 0.18288)
		(layer "In2.Cu")
		(net "M_B_CPU0_SB_DQS_DN<2>")
	)
	(segment
		(start 326.198484 -217.311732)
		(end 326.022462 -217.311732)
		(width 0.18288)
		(layer "In2.Cu")
		(net "M_B_CPU0_SB_DQS_DN<2>")
	)
	(segment
		(start 327.150476 -218.263724)
		(end 326.974454 -218.263724)
		(width 0.18288)
		(layer "In2.Cu")
		(net "M_B_CPU0_SB_DQS_DN<2>")
	)
	(segment
		(start 300.617636 -210.455002)
		(end 300.589442 -210.426808)
		(width 0.16002)
		(layer "In2.Cu")
		(net "M_B_CPU0_SB_DQS_DN<2>")
	)
	(segment
		(start 306.441348 -209.33283)
		(end 306.413154 -209.361024)
		(width 0.16002)
		(layer "In2.Cu")
		(net "M_B_CPU0_SB_DQS_DN<2>")
	)
	(segment
		(start 298.810172 -209.641694)
		(end 298.52747 -209.924396)
		(width 0.18288)
		(layer "In2.Cu")
		(net "M_B_CPU0_SB_DQS_DN<2>")
	)
	(segment
		(start 334.018636 -224.7138)
		(end 334.017874 -224.713292)
		(width 0.088646)
		(layer "In2.Cu")
		(net "M_B_CPU0_SB_DQS_DN<2>")
	)
	(segment
		(start 334.770984 -226.025964)
		(end 334.770984 -225.998786)
		(width 0.088646)
		(layer "In2.Cu")
		(net "M_B_CPU0_SB_DQS_DN<2>")
	)
	(segment
		(start 310.076088 -208.853278)
		(end 310.06034 -208.853278)
		(width 0.16002)
		(layer "In2.Cu")
		(net "M_B_CPU0_SB_DQS_DN<2>")
	)
	(segment
		(start 318.406526 -209.695796)
		(end 318.005968 -209.295238)
		(width 0.18288)
		(layer "In2.Cu")
		(net "M_B_CPU0_SB_DQS_DN<2>")
	)
	(segment
		(start 324.682612 -215.971882)
		(end 324.682612 -215.79586)
		(width 0.18288)
		(layer "In2.Cu")
		(net "M_B_CPU0_SB_DQS_DN<2>")
	)
	(segment
		(start 300.373542 -210.210908)
		(end 300.345348 -210.182714)
		(width 0.16002)
		(layer "In2.Cu")
		(net "M_B_CPU0_SB_DQS_DN<2>")
	)
	(segment
		(start 297.253914 -209.716624)
		(end 297.05427 -209.51698)
		(width 0.16002)
		(layer "In2.Cu")
		(net "M_B_CPU0_SB_DQS_DN<2>")
	)
	(segment
		(start 324.682612 -215.79586)
		(end 324.2945 -215.407748)
		(width 0.18288)
		(layer "In2.Cu")
		(net "M_B_CPU0_SB_DQS_DN<2>")
	)
	(arc
		(start 335.428082 -227.155502)
		(mid 335.291057 -227.018389)
		(end 335.240884 -226.831144)
		(width 0.088646)
		(layer "In2.Cu")
		(net "M_B_CPU0_SB_DQS_DN<2>")
	)
	(arc
		(start 334.770984 -225.998786)
		(mid 334.690822 -225.726597)
		(end 334.488536 -225.527616)
		(width 0.088646)
		(layer "In2.Cu")
		(net "M_B_CPU0_SB_DQS_DN<2>")
	)
	(arc
		(start 333.06385 -223.077278)
		(mid 332.787409 -223.010112)
		(end 332.513178 -223.085914)
		(width 0.088646)
		(layer "In2.Cu")
		(net "M_B_CPU0_SB_DQS_DN<2>")
	)
	(arc
		(start 334.009746 -224.70872)
		(mid 333.878832 -224.57236)
		(end 333.831184 -224.389442)
		(width 0.088646)
		(layer "In2.Cu")
		(net "M_B_CPU0_SB_DQS_DN<2>")
	)
	(arc
		(start 334.958182 -226.341686)
		(mid 334.823249 -226.208332)
		(end 334.770984 -226.025964)
		(width 0.088646)
		(layer "In2.Cu")
		(net "M_B_CPU0_SB_DQS_DN<2>")
	)
	(arc
		(start 333.539846 -223.894904)
		(mid 333.408932 -223.758544)
		(end 333.361284 -223.575626)
		(width 0.088646)
		(layer "In2.Cu")
		(net "M_B_CPU0_SB_DQS_DN<2>")
	)
	(arc
		(start 333.361284 -223.561402)
		(mid 333.282065 -223.286717)
		(end 333.078582 -223.085914)
		(width 0.088646)
		(layer "In2.Cu")
		(net "M_B_CPU0_SB_DQS_DN<2>")
	)
	(arc
		(start 333.831184 -224.389442)
		(mid 333.757268 -224.10994)
		(end 333.554832 -223.90354)
		(width 0.088646)
		(layer "In2.Cu")
		(net "M_B_CPU0_SB_DQS_DN<2>")
	)
	(arc
		(start 334.301084 -225.193352)
		(mid 334.222973 -224.916403)
		(end 334.018636 -224.7138)
		(width 0.088646)
		(layer "In2.Cu")
		(net "M_B_CPU0_SB_DQS_DN<2>")
	)
	(arc
		(start 335.240884 -226.831144)
		(mid 335.168649 -226.55462)
		(end 334.970374 -226.348798)
		(width 0.088646)
		(layer "In2.Cu")
		(net "M_B_CPU0_SB_DQS_DN<2>")
	)
	(arc
		(start 332.513432 -223.086676)
		(mid 332.42289 -223.124179)
		(end 332.325726 -223.136968)
		(width 0.088646)
		(layer "In2.Cu")
		(net "M_B_CPU0_SB_DQS_DN<2>")
	)
	(arc
		(start 334.479646 -225.522536)
		(mid 334.348732 -225.386176)
		(end 334.301084 -225.203258)
		(width 0.088646)
		(layer "In2.Cu")
		(net "M_B_CPU0_SB_DQS_DN<2>")
	)
	(segment
		(start 286.804354 -218.566746)
		(end 286.255714 -218.566746)
		(width 0.20066)
		(layer "F.Cu")
		(net "M_B_CPU0_SB_DQS_DN<1>")
	)
	(segment
		(start 287.065466 -218.827858)
		(end 286.804354 -218.566746)
		(width 0.20066)
		(layer "F.Cu")
		(net "M_B_CPU0_SB_DQS_DN<1>")
	)
	(segment
		(start 287.579308 -218.827858)
		(end 287.065466 -218.827858)
		(width 0.20066)
		(layer "F.Cu")
		(net "M_B_CPU0_SB_DQS_DN<1>")
	)
	(segment
		(start 291.973254 -219.253054)
		(end 291.711888 -218.991688)
		(width 0.20066)
		(layer "F.Cu")
		(net "M_B_CPU0_SB_DQS_DN<1>")
	)
	(segment
		(start 289.027362 -218.98102)
		(end 288.755328 -219.253054)
		(width 0.20066)
		(layer "F.Cu")
		(net "M_B_CPU0_SB_DQS_DN<1>")
	)
	(segment
		(start 289.243008 -218.991688)
		(end 289.23234 -218.98102)
		(width 0.101854)
		(layer "F.Cu")
		(net "M_B_CPU0_SB_DQS_DN<1>")
	)
	(segment
		(start 292.991794 -218.827858)
		(end 292.58514 -218.827858)
		(width 0.20066)
		(layer "F.Cu")
		(net "M_B_CPU0_SB_DQS_DN<1>")
	)
	(segment
		(start 289.23234 -218.98102)
		(end 289.231578 -218.98102)
		(width 0.101854)
		(layer "F.Cu")
		(net "M_B_CPU0_SB_DQS_DN<1>")
	)
	(segment
		(start 293.799514 -218.566746)
		(end 293.252906 -218.566746)
		(width 0.20066)
		(layer "F.Cu")
		(net "M_B_CPU0_SB_DQS_DN<1>")
	)
	(segment
		(start 336.085434 -233.064304)
		(end 336.085434 -232.528364)
		(width 0.20066)
		(layer "F.Cu")
		(net "M_B_CPU0_SB_DQS_DN<1>")
	)
	(segment
		(start 291.711888 -218.991688)
		(end 291.556694 -218.991688)
		(width 0.20066)
		(layer "F.Cu")
		(net "M_B_CPU0_SB_DQS_DN<1>")
	)
	(segment
		(start 292.58514 -218.827858)
		(end 292.159944 -219.253054)
		(width 0.20066)
		(layer "F.Cu")
		(net "M_B_CPU0_SB_DQS_DN<1>")
	)
	(segment
		(start 294.904414 -218.566746)
		(end 293.799514 -218.566746)
		(width 0.20066)
		(layer "F.Cu")
		(net "M_B_CPU0_SB_DQS_DN<1>")
	)
	(segment
		(start 288.21507 -219.253054)
		(end 287.579308 -218.827858)
		(width 0.20066)
		(layer "F.Cu")
		(net "M_B_CPU0_SB_DQS_DN<1>")
	)
	(segment
		(start 293.252906 -218.566746)
		(end 292.991794 -218.827858)
		(width 0.20066)
		(layer "F.Cu")
		(net "M_B_CPU0_SB_DQS_DN<1>")
	)
	(segment
		(start 289.231578 -218.98102)
		(end 289.027362 -218.98102)
		(width 0.20066)
		(layer "F.Cu")
		(net "M_B_CPU0_SB_DQS_DN<1>")
	)
	(segment
		(start 292.159944 -219.253054)
		(end 291.973254 -219.253054)
		(width 0.20066)
		(layer "F.Cu")
		(net "M_B_CPU0_SB_DQS_DN<1>")
	)
	(segment
		(start 291.556694 -218.991688)
		(end 289.243008 -218.991688)
		(width 0.1016)
		(layer "F.Cu")
		(net "M_B_CPU0_SB_DQS_DN<1>")
	)
	(segment
		(start 288.755328 -219.253054)
		(end 288.21507 -219.253054)
		(width 0.20066)
		(layer "F.Cu")
		(net "M_B_CPU0_SB_DQS_DN<1>")
	)
	(segment
		(start 310.623966 -219.245434)
		(end 310.172354 -219.245434)
		(width 0.18288)
		(layer "In2.Cu")
		(net "M_B_CPU0_SB_DQS_DN<1>")
	)
	(segment
		(start 322.636134 -223.675956)
		(end 322.248276 -223.288098)
		(width 0.18288)
		(layer "In2.Cu")
		(net "M_B_CPU0_SB_DQS_DN<1>")
	)
	(segment
		(start 335.541112 -232.73258)
		(end 335.332832 -232.852722)
		(width 0.088646)
		(layer "In2.Cu")
		(net "M_B_CPU0_SB_DQS_DN<1>")
	)
	(segment
		(start 322.812156 -223.675956)
		(end 322.636134 -223.675956)
		(width 0.18288)
		(layer "In2.Cu")
		(net "M_B_CPU0_SB_DQS_DN<1>")
	)
	(segment
		(start 295.174416 -218.836748)
		(end 294.904414 -218.566746)
		(width 0.18288)
		(layer "In2.Cu")
		(net "M_B_CPU0_SB_DQS_DN<1>")
	)
	(segment
		(start 312.01741 -218.711018)
		(end 311.989216 -218.682824)
		(width 0.16002)
		(layer "In2.Cu")
		(net "M_B_CPU0_SB_DQS_DN<1>")
	)
	(segment
		(start 302.313086 -219.577158)
		(end 302.113442 -219.776802)
		(width 0.16002)
		(layer "In2.Cu")
		(net "M_B_CPU0_SB_DQS_DN<1>")
	)
	(segment
		(start 299.454062 -219.258896)
		(end 299.186854 -218.991688)
		(width 0.18288)
		(layer "In2.Cu")
		(net "M_B_CPU0_SB_DQS_DN<1>")
	)
	(segment
		(start 302.068992 -219.804996)
		(end 301.995078 -219.87891)
		(width 0.18288)
		(layer "In2.Cu")
		(net "M_B_CPU0_SB_DQS_DN<1>")
	)
	(segment
		(start 319.95618 -220.81998)
		(end 319.780158 -220.81998)
		(width 0.18288)
		(layer "In2.Cu")
		(net "M_B_CPU0_SB_DQS_DN<1>")
	)
	(segment
		(start 320.344292 -221.208092)
		(end 319.95618 -220.81998)
		(width 0.18288)
		(layer "In2.Cu")
		(net "M_B_CPU0_SB_DQS_DN<1>")
	)
	(segment
		(start 309.856886 -219.560902)
		(end 309.856886 -219.577158)
		(width 0.16002)
		(layer "In2.Cu")
		(net "M_B_CPU0_SB_DQS_DN<1>")
	)
	(segment
		(start 313.75731 -218.926918)
		(end 313.741054 -218.926918)
		(width 0.16002)
		(layer "In2.Cu")
		(net "M_B_CPU0_SB_DQS_DN<1>")
	)
	(segment
		(start 318.440308 -219.304108)
		(end 318.052196 -218.915996)
		(width 0.18288)
		(layer "In2.Cu")
		(net "M_B_CPU0_SB_DQS_DN<1>")
	)
	(segment
		(start 300.071536 -219.258896)
		(end 299.454062 -219.258896)
		(width 0.18288)
		(layer "In2.Cu")
		(net "M_B_CPU0_SB_DQS_DN<1>")
	)
	(segment
		(start 309.612792 -219.804996)
		(end 309.536338 -219.88145)
		(width 0.18288)
		(layer "In2.Cu")
		(net "M_B_CPU0_SB_DQS_DN<1>")
	)
	(segment
		(start 314.795916 -218.528138)
		(end 314.139834 -218.528138)
		(width 0.18288)
		(layer "In2.Cu")
		(net "M_B_CPU0_SB_DQS_DN<1>")
	)
	(segment
		(start 300.617636 -219.804996)
		(end 300.589442 -219.776802)
		(width 0.16002)
		(layer "In2.Cu")
		(net "M_B_CPU0_SB_DQS_DN<1>")
	)
	(segment
		(start 298.52747 -219.27439)
		(end 297.477942 -219.27439)
		(width 0.18288)
		(layer "In2.Cu")
		(net "M_B_CPU0_SB_DQS_DN<1>")
	)
	(segment
		(start 313.741054 -218.926918)
		(end 313.71286 -218.955112)
		(width 0.16002)
		(layer "In2.Cu")
		(net "M_B_CPU0_SB_DQS_DN<1>")
	)
	(segment
		(start 296.140378 -218.581224)
		(end 295.523158 -218.836748)
		(width 0.18288)
		(layer "In2.Cu")
		(net "M_B_CPU0_SB_DQS_DN<1>")
	)
	(segment
		(start 321.860164 -222.723964)
		(end 321.684142 -222.723964)
		(width 0.18288)
		(layer "In2.Cu")
		(net "M_B_CPU0_SB_DQS_DN<1>")
	)
	(segment
		(start 298.810172 -218.991688)
		(end 298.52747 -219.27439)
		(width 0.18288)
		(layer "In2.Cu")
		(net "M_B_CPU0_SB_DQS_DN<1>")
	)
	(segment
		(start 302.097186 -219.776802)
		(end 302.068992 -219.804996)
		(width 0.16002)
		(layer "In2.Cu")
		(net "M_B_CPU0_SB_DQS_DN<1>")
	)
	(segment
		(start 304.791618 -220.729048)
		(end 304.717704 -220.655134)
		(width 0.18288)
		(layer "In2.Cu")
		(net "M_B_CPU0_SB_DQS_DN<1>")
	)
	(segment
		(start 318.052196 -218.915996)
		(end 317.876174 -218.915996)
		(width 0.18288)
		(layer "In2.Cu")
		(net "M_B_CPU0_SB_DQS_DN<1>")
	)
	(segment
		(start 331.195934 -232.235756)
		(end 323.200268 -224.24009)
		(width 0.18288)
		(layer "In2.Cu")
		(net "M_B_CPU0_SB_DQS_DN<1>")
	)
	(segment
		(start 306.095146 -220.729048)
		(end 304.791618 -220.729048)
		(width 0.18288)
		(layer "In2.Cu")
		(net "M_B_CPU0_SB_DQS_DN<1>")
	)
	(segment
		(start 297.27017 -219.066618)
		(end 297.253914 -219.066618)
		(width 0.16002)
		(layer "In2.Cu")
		(net "M_B_CPU0_SB_DQS_DN<1>")
	)
	(segment
		(start 313.71286 -218.955112)
		(end 313.638946 -219.029026)
		(width 0.18288)
		(layer "In2.Cu")
		(net "M_B_CPU0_SB_DQS_DN<1>")
	)
	(segment
		(start 316.142116 -218.528138)
		(end 315.593476 -218.528138)
		(width 0.18288)
		(layer "In2.Cu")
		(net "M_B_CPU0_SB_DQS_DN<1>")
	)
	(segment
		(start 315.593476 -218.528138)
		(end 315.469016 -218.403678)
		(width 0.18288)
		(layer "In2.Cu")
		(net "M_B_CPU0_SB_DQS_DN<1>")
	)
	(segment
		(start 319.004188 -219.867988)
		(end 318.828166 -219.867988)
		(width 0.18288)
		(layer "In2.Cu")
		(net "M_B_CPU0_SB_DQS_DN<1>")
	)
	(segment
		(start 322.248276 -223.288098)
		(end 322.248276 -223.112076)
		(width 0.18288)
		(layer "In2.Cu")
		(net "M_B_CPU0_SB_DQS_DN<1>")
	)
	(segment
		(start 312.217054 -218.926918)
		(end 312.01741 -218.727274)
		(width 0.16002)
		(layer "In2.Cu")
		(net "M_B_CPU0_SB_DQS_DN<1>")
	)
	(segment
		(start 316.266576 -218.403678)
		(end 316.142116 -218.528138)
		(width 0.18288)
		(layer "In2.Cu")
		(net "M_B_CPU0_SB_DQS_DN<1>")
	)
	(segment
		(start 314.920376 -218.403678)
		(end 314.795916 -218.528138)
		(width 0.18288)
		(layer "In2.Cu")
		(net "M_B_CPU0_SB_DQS_DN<1>")
	)
	(segment
		(start 319.3923 -220.2561)
		(end 319.004188 -219.867988)
		(width 0.18288)
		(layer "In2.Cu")
		(net "M_B_CPU0_SB_DQS_DN<1>")
	)
	(segment
		(start 302.34128 -219.532708)
		(end 302.313086 -219.560902)
		(width 0.16002)
		(layer "In2.Cu")
		(net "M_B_CPU0_SB_DQS_DN<1>")
	)
	(segment
		(start 316.939676 -218.528138)
		(end 316.815216 -218.403678)
		(width 0.18288)
		(layer "In2.Cu")
		(net "M_B_CPU0_SB_DQS_DN<1>")
	)
	(segment
		(start 315.469016 -218.403678)
		(end 314.920376 -218.403678)
		(width 0.18288)
		(layer "In2.Cu")
		(net "M_B_CPU0_SB_DQS_DN<1>")
	)
	(segment
		(start 297.05427 -218.850718)
		(end 297.026076 -218.822524)
		(width 0.16002)
		(layer "In2.Cu")
		(net "M_B_CPU0_SB_DQS_DN<1>")
	)
	(segment
		(start 306.441348 -220.382846)
		(end 306.413154 -220.41104)
		(width 0.16002)
		(layer "In2.Cu")
		(net "M_B_CPU0_SB_DQS_DN<1>")
	)
	(segment
		(start 304.673254 -220.62694)
		(end 304.47361 -220.427296)
		(width 0.16002)
		(layer "In2.Cu")
		(net "M_B_CPU0_SB_DQS_DN<1>")
	)
	(segment
		(start 302.313086 -219.560902)
		(end 302.313086 -219.577158)
		(width 0.16002)
		(layer "In2.Cu")
		(net "M_B_CPU0_SB_DQS_DN<1>")
	)
	(segment
		(start 297.05427 -218.866974)
		(end 297.05427 -218.850718)
		(width 0.16002)
		(layer "In2.Cu")
		(net "M_B_CPU0_SB_DQS_DN<1>")
	)
	(segment
		(start 304.47361 -220.41104)
		(end 304.445416 -220.382846)
		(width 0.16002)
		(layer "In2.Cu")
		(net "M_B_CPU0_SB_DQS_DN<1>")
	)
	(segment
		(start 301.995078 -219.87891)
		(end 300.69155 -219.87891)
		(width 0.18288)
		(layer "In2.Cu")
		(net "M_B_CPU0_SB_DQS_DN<1>")
	)
	(segment
		(start 309.856886 -219.577158)
		(end 309.657242 -219.776802)
		(width 0.16002)
		(layer "In2.Cu")
		(net "M_B_CPU0_SB_DQS_DN<1>")
	)
	(segment
		(start 314.139834 -218.528138)
		(end 313.985148 -218.682824)
		(width 0.18288)
		(layer "In2.Cu")
		(net "M_B_CPU0_SB_DQS_DN<1>")
	)
	(segment
		(start 308.18201 -219.88145)
		(end 307.88991 -219.58935)
		(width 0.18288)
		(layer "In2.Cu")
		(net "M_B_CPU0_SB_DQS_DN<1>")
	)
	(segment
		(start 313.638946 -219.029026)
		(end 312.335418 -219.029026)
		(width 0.18288)
		(layer "In2.Cu")
		(net "M_B_CPU0_SB_DQS_DN<1>")
	)
	(segment
		(start 313.985148 -218.682824)
		(end 313.956954 -218.711018)
		(width 0.16002)
		(layer "In2.Cu")
		(net "M_B_CPU0_SB_DQS_DN<1>")
	)
	(segment
		(start 297.477942 -219.27439)
		(end 297.298364 -219.094812)
		(width 0.18288)
		(layer "In2.Cu")
		(net "M_B_CPU0_SB_DQS_DN<1>")
	)
	(segment
		(start 303.3903 -219.32773)
		(end 302.546258 -219.32773)
		(width 0.18288)
		(layer "In2.Cu")
		(net "M_B_CPU0_SB_DQS_DN<1>")
	)
	(segment
		(start 299.186854 -218.991688)
		(end 298.810172 -218.991688)
		(width 0.18288)
		(layer "In2.Cu")
		(net "M_B_CPU0_SB_DQS_DN<1>")
	)
	(segment
		(start 312.335418 -219.029026)
		(end 312.261504 -218.955112)
		(width 0.18288)
		(layer "In2.Cu")
		(net "M_B_CPU0_SB_DQS_DN<1>")
	)
	(segment
		(start 320.73215 -221.771972)
		(end 320.344292 -221.384114)
		(width 0.18288)
		(layer "In2.Cu")
		(net "M_B_CPU0_SB_DQS_DN<1>")
	)
	(segment
		(start 306.197254 -220.62694)
		(end 306.16906 -220.655134)
		(width 0.16002)
		(layer "In2.Cu")
		(net "M_B_CPU0_SB_DQS_DN<1>")
	)
	(segment
		(start 334.018636 -232.852722)
		(end 334.008222 -232.846626)
		(width 0.088646)
		(layer "In2.Cu")
		(net "M_B_CPU0_SB_DQS_DN<1>")
	)
	(segment
		(start 322.248276 -223.112076)
		(end 321.860164 -222.723964)
		(width 0.18288)
		(layer "In2.Cu")
		(net "M_B_CPU0_SB_DQS_DN<1>")
	)
	(segment
		(start 313.956954 -218.727274)
		(end 313.75731 -218.926918)
		(width 0.16002)
		(layer "In2.Cu")
		(net "M_B_CPU0_SB_DQS_DN<1>")
	)
	(segment
		(start 297.253914 -219.066618)
		(end 297.05427 -218.866974)
		(width 0.16002)
		(layer "In2.Cu")
		(net "M_B_CPU0_SB_DQS_DN<1>")
	)
	(segment
		(start 318.828166 -219.867988)
		(end 318.440308 -219.48013)
		(width 0.18288)
		(layer "In2.Cu")
		(net "M_B_CPU0_SB_DQS_DN<1>")
	)
	(segment
		(start 331.6351 -232.475024)
		(end 331.350874 -232.475024)
		(width 0.088646)
		(layer "In2.Cu")
		(net "M_B_CPU0_SB_DQS_DN<1>")
	)
	(segment
		(start 297.298364 -219.094812)
		(end 297.27017 -219.066618)
		(width 0.16002)
		(layer "In2.Cu")
		(net "M_B_CPU0_SB_DQS_DN<1>")
	)
	(segment
		(start 306.413154 -220.41104)
		(end 306.413154 -220.427296)
		(width 0.16002)
		(layer "In2.Cu")
		(net "M_B_CPU0_SB_DQS_DN<1>")
	)
	(segment
		(start 310.172354 -219.245434)
		(end 309.88508 -219.532708)
		(width 0.18288)
		(layer "In2.Cu")
		(net "M_B_CPU0_SB_DQS_DN<1>")
	)
	(segment
		(start 320.344292 -221.384114)
		(end 320.344292 -221.208092)
		(width 0.18288)
		(layer "In2.Cu")
		(net "M_B_CPU0_SB_DQS_DN<1>")
	)
	(segment
		(start 295.523158 -218.836748)
		(end 295.174416 -218.836748)
		(width 0.18288)
		(layer "In2.Cu")
		(net "M_B_CPU0_SB_DQS_DN<1>")
	)
	(segment
		(start 323.200268 -224.064068)
		(end 322.812156 -223.675956)
		(width 0.18288)
		(layer "In2.Cu")
		(net "M_B_CPU0_SB_DQS_DN<1>")
	)
	(segment
		(start 300.373542 -219.577158)
		(end 300.373542 -219.560902)
		(width 0.16002)
		(layer "In2.Cu")
		(net "M_B_CPU0_SB_DQS_DN<1>")
	)
	(segment
		(start 311.989216 -218.682824)
		(end 311.842912 -218.53652)
		(width 0.18288)
		(layer "In2.Cu")
		(net "M_B_CPU0_SB_DQS_DN<1>")
	)
	(segment
		(start 319.3923 -220.432122)
		(end 319.3923 -220.2561)
		(width 0.18288)
		(layer "In2.Cu")
		(net "M_B_CPU0_SB_DQS_DN<1>")
	)
	(segment
		(start 300.373542 -219.560902)
		(end 300.345348 -219.532708)
		(width 0.16002)
		(layer "In2.Cu")
		(net "M_B_CPU0_SB_DQS_DN<1>")
	)
	(segment
		(start 307.88991 -219.58935)
		(end 307.234844 -219.58935)
		(width 0.18288)
		(layer "In2.Cu")
		(net "M_B_CPU0_SB_DQS_DN<1>")
	)
	(segment
		(start 309.536338 -219.88145)
		(end 308.18201 -219.88145)
		(width 0.18288)
		(layer "In2.Cu")
		(net "M_B_CPU0_SB_DQS_DN<1>")
	)
	(segment
		(start 302.113442 -219.776802)
		(end 302.097186 -219.776802)
		(width 0.16002)
		(layer "In2.Cu")
		(net "M_B_CPU0_SB_DQS_DN<1>")
	)
	(segment
		(start 311.842912 -218.53652)
		(end 311.33288 -218.53652)
		(width 0.18288)
		(layer "In2.Cu")
		(net "M_B_CPU0_SB_DQS_DN<1>")
	)
	(segment
		(start 335.881218 -232.73258)
		(end 335.541112 -232.73258)
		(width 0.088646)
		(layer "In2.Cu")
		(net "M_B_CPU0_SB_DQS_DN<1>")
	)
	(segment
		(start 296.784776 -218.581224)
		(end 296.140378 -218.581224)
		(width 0.18288)
		(layer "In2.Cu")
		(net "M_B_CPU0_SB_DQS_DN<1>")
	)
	(segment
		(start 312.261504 -218.955112)
		(end 312.23331 -218.926918)
		(width 0.16002)
		(layer "In2.Cu")
		(net "M_B_CPU0_SB_DQS_DN<1>")
	)
	(segment
		(start 332.32598 -232.903014)
		(end 332.06309 -232.903014)
		(width 0.088646)
		(layer "In2.Cu")
		(net "M_B_CPU0_SB_DQS_DN<1>")
	)
	(segment
		(start 306.21351 -220.62694)
		(end 306.197254 -220.62694)
		(width 0.16002)
		(layer "In2.Cu")
		(net "M_B_CPU0_SB_DQS_DN<1>")
	)
	(segment
		(start 309.88508 -219.532708)
		(end 309.856886 -219.560902)
		(width 0.16002)
		(layer "In2.Cu")
		(net "M_B_CPU0_SB_DQS_DN<1>")
	)
	(segment
		(start 321.684142 -222.723964)
		(end 321.296284 -222.336106)
		(width 0.18288)
		(layer "In2.Cu")
		(net "M_B_CPU0_SB_DQS_DN<1>")
	)
	(segment
		(start 306.413154 -220.427296)
		(end 306.21351 -220.62694)
		(width 0.16002)
		(layer "In2.Cu")
		(net "M_B_CPU0_SB_DQS_DN<1>")
	)
	(segment
		(start 313.956954 -218.711018)
		(end 313.956954 -218.727274)
		(width 0.16002)
		(layer "In2.Cu")
		(net "M_B_CPU0_SB_DQS_DN<1>")
	)
	(segment
		(start 300.69155 -219.87891)
		(end 300.617636 -219.804996)
		(width 0.18288)
		(layer "In2.Cu")
		(net "M_B_CPU0_SB_DQS_DN<1>")
	)
	(segment
		(start 321.296284 -222.160084)
		(end 320.908172 -221.771972)
		(width 0.18288)
		(layer "In2.Cu")
		(net "M_B_CPU0_SB_DQS_DN<1>")
	)
	(segment
		(start 331.350874 -232.475024)
		(end 331.195934 -232.320084)
		(width 0.088646)
		(layer "In2.Cu")
		(net "M_B_CPU0_SB_DQS_DN<1>")
	)
	(segment
		(start 319.780158 -220.81998)
		(end 319.3923 -220.432122)
		(width 0.18288)
		(layer "In2.Cu")
		(net "M_B_CPU0_SB_DQS_DN<1>")
	)
	(segment
		(start 304.717704 -220.655134)
		(end 304.68951 -220.62694)
		(width 0.16002)
		(layer "In2.Cu")
		(net "M_B_CPU0_SB_DQS_DN<1>")
	)
	(segment
		(start 332.06309 -232.903014)
		(end 331.6351 -232.475024)
		(width 0.088646)
		(layer "In2.Cu")
		(net "M_B_CPU0_SB_DQS_DN<1>")
	)
	(segment
		(start 312.23331 -218.926918)
		(end 312.217054 -218.926918)
		(width 0.16002)
		(layer "In2.Cu")
		(net "M_B_CPU0_SB_DQS_DN<1>")
	)
	(segment
		(start 316.815216 -218.403678)
		(end 316.266576 -218.403678)
		(width 0.18288)
		(layer "In2.Cu")
		(net "M_B_CPU0_SB_DQS_DN<1>")
	)
	(segment
		(start 306.16906 -220.655134)
		(end 306.095146 -220.729048)
		(width 0.18288)
		(layer "In2.Cu")
		(net "M_B_CPU0_SB_DQS_DN<1>")
	)
	(segment
		(start 309.640986 -219.776802)
		(end 309.612792 -219.804996)
		(width 0.16002)
		(layer "In2.Cu")
		(net "M_B_CPU0_SB_DQS_DN<1>")
	)
	(segment
		(start 331.195934 -232.320084)
		(end 331.195934 -232.235756)
		(width 0.088646)
		(layer "In2.Cu")
		(net "M_B_CPU0_SB_DQS_DN<1>")
	)
	(segment
		(start 312.01741 -218.727274)
		(end 312.01741 -218.711018)
		(width 0.16002)
		(layer "In2.Cu")
		(net "M_B_CPU0_SB_DQS_DN<1>")
	)
	(segment
		(start 321.296284 -222.336106)
		(end 321.296284 -222.160084)
		(width 0.18288)
		(layer "In2.Cu")
		(net "M_B_CPU0_SB_DQS_DN<1>")
	)
	(segment
		(start 304.68951 -220.62694)
		(end 304.673254 -220.62694)
		(width 0.16002)
		(layer "In2.Cu")
		(net "M_B_CPU0_SB_DQS_DN<1>")
	)
	(segment
		(start 302.546258 -219.32773)
		(end 302.34128 -219.532708)
		(width 0.18288)
		(layer "In2.Cu")
		(net "M_B_CPU0_SB_DQS_DN<1>")
	)
	(segment
		(start 304.445416 -220.382846)
		(end 303.3903 -219.32773)
		(width 0.18288)
		(layer "In2.Cu")
		(net "M_B_CPU0_SB_DQS_DN<1>")
	)
	(segment
		(start 300.573186 -219.776802)
		(end 300.373542 -219.577158)
		(width 0.16002)
		(layer "In2.Cu")
		(net "M_B_CPU0_SB_DQS_DN<1>")
	)
	(segment
		(start 318.440308 -219.48013)
		(end 318.440308 -219.304108)
		(width 0.18288)
		(layer "In2.Cu")
		(net "M_B_CPU0_SB_DQS_DN<1>")
	)
	(segment
		(start 311.33288 -218.53652)
		(end 310.623966 -219.245434)
		(width 0.18288)
		(layer "In2.Cu")
		(net "M_B_CPU0_SB_DQS_DN<1>")
	)
	(segment
		(start 307.234844 -219.58935)
		(end 306.441348 -220.382846)
		(width 0.18288)
		(layer "In2.Cu")
		(net "M_B_CPU0_SB_DQS_DN<1>")
	)
	(segment
		(start 309.657242 -219.776802)
		(end 309.640986 -219.776802)
		(width 0.16002)
		(layer "In2.Cu")
		(net "M_B_CPU0_SB_DQS_DN<1>")
	)
	(segment
		(start 320.908172 -221.771972)
		(end 320.73215 -221.771972)
		(width 0.18288)
		(layer "In2.Cu")
		(net "M_B_CPU0_SB_DQS_DN<1>")
	)
	(segment
		(start 336.085434 -232.528364)
		(end 335.881218 -232.73258)
		(width 0.088646)
		(layer "In2.Cu")
		(net "M_B_CPU0_SB_DQS_DN<1>")
	)
	(segment
		(start 304.47361 -220.427296)
		(end 304.47361 -220.41104)
		(width 0.16002)
		(layer "In2.Cu")
		(net "M_B_CPU0_SB_DQS_DN<1>")
	)
	(segment
		(start 297.026076 -218.822524)
		(end 296.784776 -218.581224)
		(width 0.18288)
		(layer "In2.Cu")
		(net "M_B_CPU0_SB_DQS_DN<1>")
	)
	(segment
		(start 317.876174 -218.915996)
		(end 317.488316 -218.528138)
		(width 0.18288)
		(layer "In2.Cu")
		(net "M_B_CPU0_SB_DQS_DN<1>")
	)
	(segment
		(start 300.345348 -219.532708)
		(end 300.071536 -219.258896)
		(width 0.18288)
		(layer "In2.Cu")
		(net "M_B_CPU0_SB_DQS_DN<1>")
	)
	(segment
		(start 333.078582 -232.852722)
		(end 333.06385 -232.844086)
		(width 0.088646)
		(layer "In2.Cu")
		(net "M_B_CPU0_SB_DQS_DN<1>")
	)
	(segment
		(start 323.200268 -224.24009)
		(end 323.200268 -224.064068)
		(width 0.18288)
		(layer "In2.Cu")
		(net "M_B_CPU0_SB_DQS_DN<1>")
	)
	(segment
		(start 317.488316 -218.528138)
		(end 316.939676 -218.528138)
		(width 0.18288)
		(layer "In2.Cu")
		(net "M_B_CPU0_SB_DQS_DN<1>")
	)
	(segment
		(start 300.589442 -219.776802)
		(end 300.573186 -219.776802)
		(width 0.16002)
		(layer "In2.Cu")
		(net "M_B_CPU0_SB_DQS_DN<1>")
	)
	(arc
		(start 333.06385 -232.844086)
		(mid 332.787375 -232.776766)
		(end 332.513178 -232.852722)
		(width 0.088646)
		(layer "In2.Cu")
		(net "M_B_CPU0_SB_DQS_DN<1>")
	)
	(arc
		(start 333.452978 -232.852722)
		(mid 333.26578 -232.902865)
		(end 333.078582 -232.852722)
		(width 0.088646)
		(layer "In2.Cu")
		(net "M_B_CPU0_SB_DQS_DN<1>")
	)
	(arc
		(start 334.393032 -232.852722)
		(mid 334.205834 -232.902865)
		(end 334.018636 -232.852722)
		(width 0.088646)
		(layer "In2.Cu")
		(net "M_B_CPU0_SB_DQS_DN<1>")
	)
	(arc
		(start 334.008222 -232.846626)
		(mid 333.72979 -232.77678)
		(end 333.452978 -232.852722)
		(width 0.088646)
		(layer "In2.Cu")
		(net "M_B_CPU0_SB_DQS_DN<1>")
	)
	(arc
		(start 335.332832 -232.852722)
		(mid 335.145634 -232.902865)
		(end 334.958436 -232.852722)
		(width 0.088646)
		(layer "In2.Cu")
		(net "M_B_CPU0_SB_DQS_DN<1>")
	)
	(arc
		(start 334.958436 -232.852722)
		(mid 334.675734 -232.776946)
		(end 334.393032 -232.852722)
		(width 0.088646)
		(layer "In2.Cu")
		(net "M_B_CPU0_SB_DQS_DN<1>")
	)
	(arc
		(start 332.513178 -232.852722)
		(mid 332.422886 -232.890174)
		(end 332.32598 -232.903014)
		(width 0.088646)
		(layer "In2.Cu")
		(net "M_B_CPU0_SB_DQS_DN<1>")
	)
	(segment
		(start 339.374734 -235.506006)
		(end 339.37448 -235.505752)
		(width 0.20066)
		(layer "F.Cu")
		(net "M_B_CPU0_SB_DQS_DN<0>")
	)
	(segment
		(start 287.065466 -228.177852)
		(end 286.804354 -227.91674)
		(width 0.20066)
		(layer "F.Cu")
		(net "M_B_CPU0_SB_DQS_DN<0>")
	)
	(segment
		(start 288.215324 -228.603048)
		(end 287.579308 -228.177852)
		(width 0.20066)
		(layer "F.Cu")
		(net "M_B_CPU0_SB_DQS_DN<0>")
	)
	(segment
		(start 291.711888 -228.341682)
		(end 291.556694 -228.341682)
		(width 0.20066)
		(layer "F.Cu")
		(net "M_B_CPU0_SB_DQS_DN<0>")
	)
	(segment
		(start 287.579308 -228.177852)
		(end 287.065466 -228.177852)
		(width 0.20066)
		(layer "F.Cu")
		(net "M_B_CPU0_SB_DQS_DN<0>")
	)
	(segment
		(start 292.159944 -228.603048)
		(end 291.973254 -228.603048)
		(width 0.20066)
		(layer "F.Cu")
		(net "M_B_CPU0_SB_DQS_DN<0>")
	)
	(segment
		(start 294.904414 -227.91674)
		(end 293.799514 -227.91674)
		(width 0.20066)
		(layer "F.Cu")
		(net "M_B_CPU0_SB_DQS_DN<0>")
	)
	(segment
		(start 286.804354 -227.91674)
		(end 286.255714 -227.91674)
		(width 0.20066)
		(layer "F.Cu")
		(net "M_B_CPU0_SB_DQS_DN<0>")
	)
	(segment
		(start 289.23234 -228.331014)
		(end 289.231578 -228.331014)
		(width 0.101854)
		(layer "F.Cu")
		(net "M_B_CPU0_SB_DQS_DN<0>")
	)
	(segment
		(start 291.973254 -228.603048)
		(end 291.711888 -228.341682)
		(width 0.20066)
		(layer "F.Cu")
		(net "M_B_CPU0_SB_DQS_DN<0>")
	)
	(segment
		(start 293.799514 -227.91674)
		(end 293.252906 -227.91674)
		(width 0.20066)
		(layer "F.Cu")
		(net "M_B_CPU0_SB_DQS_DN<0>")
	)
	(segment
		(start 293.252906 -227.91674)
		(end 292.991794 -228.177852)
		(width 0.20066)
		(layer "F.Cu")
		(net "M_B_CPU0_SB_DQS_DN<0>")
	)
	(segment
		(start 289.027362 -228.331014)
		(end 288.755328 -228.603048)
		(width 0.20066)
		(layer "F.Cu")
		(net "M_B_CPU0_SB_DQS_DN<0>")
	)
	(segment
		(start 292.58514 -228.177852)
		(end 292.159944 -228.603048)
		(width 0.20066)
		(layer "F.Cu")
		(net "M_B_CPU0_SB_DQS_DN<0>")
	)
	(segment
		(start 292.991794 -228.177852)
		(end 292.58514 -228.177852)
		(width 0.20066)
		(layer "F.Cu")
		(net "M_B_CPU0_SB_DQS_DN<0>")
	)
	(segment
		(start 288.755328 -228.603048)
		(end 288.215324 -228.603048)
		(width 0.20066)
		(layer "F.Cu")
		(net "M_B_CPU0_SB_DQS_DN<0>")
	)
	(segment
		(start 291.556694 -228.341682)
		(end 289.243008 -228.341682)
		(width 0.1016)
		(layer "F.Cu")
		(net "M_B_CPU0_SB_DQS_DN<0>")
	)
	(segment
		(start 339.37448 -235.505752)
		(end 339.37448 -234.970066)
		(width 0.20066)
		(layer "F.Cu")
		(net "M_B_CPU0_SB_DQS_DN<0>")
	)
	(segment
		(start 289.243008 -228.341682)
		(end 289.23234 -228.331014)
		(width 0.101854)
		(layer "F.Cu")
		(net "M_B_CPU0_SB_DQS_DN<0>")
	)
	(segment
		(start 289.231578 -228.331014)
		(end 289.027362 -228.331014)
		(width 0.20066)
		(layer "F.Cu")
		(net "M_B_CPU0_SB_DQS_DN<0>")
	)
	(segment
		(start 302.179482 -227.722176)
		(end 302.055022 -227.846636)
		(width 0.18288)
		(layer "In4.Cu")
		(net "M_B_CPU0_SB_DQS_DN<0>")
	)
	(segment
		(start 321.381374 -234.278678)
		(end 321.205352 -234.278678)
		(width 0.18288)
		(layer "In4.Cu")
		(net "M_B_CPU0_SB_DQS_DN<0>")
	)
	(segment
		(start 312.191654 -227.635562)
		(end 311.457848 -226.901756)
		(width 0.18288)
		(layer "In4.Cu")
		(net "M_B_CPU0_SB_DQS_DN<0>")
	)
	(segment
		(start 332.32598 -235.218732)
		(end 332.091792 -235.218732)
		(width 0.088646)
		(layer "In4.Cu")
		(net "M_B_CPU0_SB_DQS_DN<0>")
	)
	(segment
		(start 307.133498 -226.259898)
		(end 306.745132 -226.648264)
		(width 0.18288)
		(layer "In4.Cu")
		(net "M_B_CPU0_SB_DQS_DN<0>")
	)
	(segment
		(start 319.865502 -232.762806)
		(end 319.47739 -232.374694)
		(width 0.18288)
		(layer "In4.Cu")
		(net "M_B_CPU0_SB_DQS_DN<0>")
	)
	(segment
		(start 295.381426 -228.175312)
		(end 295.162986 -228.175312)
		(width 0.18288)
		(layer "In4.Cu")
		(net "M_B_CPU0_SB_DQS_DN<0>")
	)
	(segment
		(start 304.198782 -227.846636)
		(end 304.074322 -227.722176)
		(width 0.18288)
		(layer "In4.Cu")
		(net "M_B_CPU0_SB_DQS_DN<0>")
	)
	(segment
		(start 296.95775 -227.945188)
		(end 296.83329 -227.820728)
		(width 0.18288)
		(layer "In4.Cu")
		(net "M_B_CPU0_SB_DQS_DN<0>")
	)
	(segment
		(start 306.180236 -226.648264)
		(end 305.933856 -226.894644)
		(width 0.18288)
		(layer "In4.Cu")
		(net "M_B_CPU0_SB_DQS_DN<0>")
	)
	(segment
		(start 317.009526 -230.082852)
		(end 317.009526 -229.90683)
		(width 0.18288)
		(layer "In4.Cu")
		(net "M_B_CPU0_SB_DQS_DN<0>")
	)
	(segment
		(start 314.287154 -228.34473)
		(end 313.866022 -228.34473)
		(width 0.18288)
		(layer "In4.Cu")
		(net "M_B_CPU0_SB_DQS_DN<0>")
	)
	(segment
		(start 301.506382 -227.846636)
		(end 301.011336 -228.341682)
		(width 0.18288)
		(layer "In4.Cu")
		(net "M_B_CPU0_SB_DQS_DN<0>")
	)
	(segment
		(start 317.573406 -230.47071)
		(end 317.397384 -230.47071)
		(width 0.18288)
		(layer "In4.Cu")
		(net "M_B_CPU0_SB_DQS_DN<0>")
	)
	(segment
		(start 333.548482 -235.294424)
		(end 333.53375 -235.285788)
		(width 0.088646)
		(layer "In4.Cu")
		(net "M_B_CPU0_SB_DQS_DN<0>")
	)
	(segment
		(start 312.367676 -227.635562)
		(end 312.191654 -227.635562)
		(width 0.18288)
		(layer "In4.Cu")
		(net "M_B_CPU0_SB_DQS_DN<0>")
	)
	(segment
		(start 316.621414 -229.518718)
		(end 316.445392 -229.518718)
		(width 0.18288)
		(layer "In4.Cu")
		(net "M_B_CPU0_SB_DQS_DN<0>")
	)
	(segment
		(start 304.981864 -227.846636)
		(end 304.198782 -227.846636)
		(width 0.18288)
		(layer "In4.Cu")
		(net "M_B_CPU0_SB_DQS_DN<0>")
	)
	(segment
		(start 295.162986 -228.175312)
		(end 294.904414 -227.91674)
		(width 0.18288)
		(layer "In4.Cu")
		(net "M_B_CPU0_SB_DQS_DN<0>")
	)
	(segment
		(start 305.757834 -226.894644)
		(end 305.369722 -227.282756)
		(width 0.18288)
		(layer "In4.Cu")
		(net "M_B_CPU0_SB_DQS_DN<0>")
	)
	(segment
		(start 321.769486 -234.842812)
		(end 321.769486 -234.66679)
		(width 0.18288)
		(layer "In4.Cu")
		(net "M_B_CPU0_SB_DQS_DN<0>")
	)
	(segment
		(start 336.367882 -235.294424)
		(end 336.35315 -235.285788)
		(width 0.088646)
		(layer "In4.Cu")
		(net "M_B_CPU0_SB_DQS_DN<0>")
	)
	(segment
		(start 319.301368 -232.374694)
		(end 318.91351 -231.986836)
		(width 0.18288)
		(layer "In4.Cu")
		(net "M_B_CPU0_SB_DQS_DN<0>")
	)
	(segment
		(start 302.728122 -227.722176)
		(end 302.179482 -227.722176)
		(width 0.18288)
		(layer "In4.Cu")
		(net "M_B_CPU0_SB_DQS_DN<0>")
	)
	(segment
		(start 302.055022 -227.846636)
		(end 301.506382 -227.846636)
		(width 0.18288)
		(layer "In4.Cu")
		(net "M_B_CPU0_SB_DQS_DN<0>")
	)
	(segment
		(start 317.009526 -229.90683)
		(end 316.621414 -229.518718)
		(width 0.18288)
		(layer "In4.Cu")
		(net "M_B_CPU0_SB_DQS_DN<0>")
	)
	(segment
		(start 305.369722 -227.458778)
		(end 304.981864 -227.846636)
		(width 0.18288)
		(layer "In4.Cu")
		(net "M_B_CPU0_SB_DQS_DN<0>")
	)
	(segment
		(start 318.91351 -231.810814)
		(end 318.525398 -231.422702)
		(width 0.18288)
		(layer "In4.Cu")
		(net "M_B_CPU0_SB_DQS_DN<0>")
	)
	(segment
		(start 313.623198 -228.587554)
		(end 313.143646 -228.587554)
		(width 0.18288)
		(layer "In4.Cu")
		(net "M_B_CPU0_SB_DQS_DN<0>")
	)
	(segment
		(start 309.105554 -226.90709)
		(end 308.458362 -226.259898)
		(width 0.18288)
		(layer "In4.Cu")
		(net "M_B_CPU0_SB_DQS_DN<0>")
	)
	(segment
		(start 318.91351 -231.986836)
		(end 318.91351 -231.810814)
		(width 0.18288)
		(layer "In4.Cu")
		(net "M_B_CPU0_SB_DQS_DN<0>")
	)
	(segment
		(start 305.369722 -227.282756)
		(end 305.369722 -227.458778)
		(width 0.18288)
		(layer "In4.Cu")
		(net "M_B_CPU0_SB_DQS_DN<0>")
	)
	(segment
		(start 320.429382 -233.326686)
		(end 320.25336 -233.326686)
		(width 0.18288)
		(layer "In4.Cu")
		(net "M_B_CPU0_SB_DQS_DN<0>")
	)
	(segment
		(start 332.020164 -235.29036)
		(end 330.746354 -235.29036)
		(width 0.088646)
		(layer "In4.Cu")
		(net "M_B_CPU0_SB_DQS_DN<0>")
	)
	(segment
		(start 318.349376 -231.422702)
		(end 317.961518 -231.034844)
		(width 0.18288)
		(layer "In4.Cu")
		(net "M_B_CPU0_SB_DQS_DN<0>")
	)
	(segment
		(start 296.28465 -227.820728)
		(end 296.16019 -227.945188)
		(width 0.18288)
		(layer "In4.Cu")
		(net "M_B_CPU0_SB_DQS_DN<0>")
	)
	(segment
		(start 337.307682 -235.294424)
		(end 337.29295 -235.285788)
		(width 0.088646)
		(layer "In4.Cu")
		(net "M_B_CPU0_SB_DQS_DN<0>")
	)
	(segment
		(start 320.25336 -233.326686)
		(end 319.865502 -232.938828)
		(width 0.18288)
		(layer "In4.Cu")
		(net "M_B_CPU0_SB_DQS_DN<0>")
	)
	(segment
		(start 296.16019 -227.945188)
		(end 295.61155 -227.945188)
		(width 0.18288)
		(layer "In4.Cu")
		(net "M_B_CPU0_SB_DQS_DN<0>")
	)
	(segment
		(start 297.505374 -227.945188)
		(end 296.95775 -227.945188)
		(width 0.18288)
		(layer "In4.Cu")
		(net "M_B_CPU0_SB_DQS_DN<0>")
	)
	(segment
		(start 304.074322 -227.722176)
		(end 303.525682 -227.722176)
		(width 0.18288)
		(layer "In4.Cu")
		(net "M_B_CPU0_SB_DQS_DN<0>")
	)
	(segment
		(start 322.157344 -235.23067)
		(end 321.769486 -234.842812)
		(width 0.18288)
		(layer "In4.Cu")
		(net "M_B_CPU0_SB_DQS_DN<0>")
	)
	(segment
		(start 339.37448 -234.970066)
		(end 339.34273 -235.08589)
		(width 0.088646)
		(layer "In4.Cu")
		(net "M_B_CPU0_SB_DQS_DN<0>")
	)
	(segment
		(start 313.866022 -228.34473)
		(end 313.623198 -228.587554)
		(width 0.18288)
		(layer "In4.Cu")
		(net "M_B_CPU0_SB_DQS_DN<0>")
	)
	(segment
		(start 305.933856 -226.894644)
		(end 305.757834 -226.894644)
		(width 0.18288)
		(layer "In4.Cu")
		(net "M_B_CPU0_SB_DQS_DN<0>")
	)
	(segment
		(start 321.205352 -234.278678)
		(end 320.817494 -233.89082)
		(width 0.18288)
		(layer "In4.Cu")
		(net "M_B_CPU0_SB_DQS_DN<0>")
	)
	(segment
		(start 303.401222 -227.846636)
		(end 302.852582 -227.846636)
		(width 0.18288)
		(layer "In4.Cu")
		(net "M_B_CPU0_SB_DQS_DN<0>")
	)
	(segment
		(start 298.477178 -228.645974)
		(end 298.20616 -228.645974)
		(width 0.18288)
		(layer "In4.Cu")
		(net "M_B_CPU0_SB_DQS_DN<0>")
	)
	(segment
		(start 317.961518 -230.858822)
		(end 317.573406 -230.47071)
		(width 0.18288)
		(layer "In4.Cu")
		(net "M_B_CPU0_SB_DQS_DN<0>")
	)
	(segment
		(start 315.516768 -228.590094)
		(end 314.532518 -228.590094)
		(width 0.18288)
		(layer "In4.Cu")
		(net "M_B_CPU0_SB_DQS_DN<0>")
	)
	(segment
		(start 320.817494 -233.714798)
		(end 320.429382 -233.326686)
		(width 0.18288)
		(layer "In4.Cu")
		(net "M_B_CPU0_SB_DQS_DN<0>")
	)
	(segment
		(start 330.686664 -235.23067)
		(end 330.648564 -235.23067)
		(width 0.088646)
		(layer "In4.Cu")
		(net "M_B_CPU0_SB_DQS_DN<0>")
	)
	(segment
		(start 298.20616 -228.645974)
		(end 297.505374 -227.945188)
		(width 0.18288)
		(layer "In4.Cu")
		(net "M_B_CPU0_SB_DQS_DN<0>")
	)
	(segment
		(start 339.149182 -235.148882)
		(end 338.875624 -235.148882)
		(width 0.088646)
		(layer "In4.Cu")
		(net "M_B_CPU0_SB_DQS_DN<0>")
	)
	(segment
		(start 309.793132 -226.64166)
		(end 309.527702 -226.90709)
		(width 0.18288)
		(layer "In4.Cu")
		(net "M_B_CPU0_SB_DQS_DN<0>")
	)
	(segment
		(start 317.397384 -230.47071)
		(end 317.009526 -230.082852)
		(width 0.18288)
		(layer "In4.Cu")
		(net "M_B_CPU0_SB_DQS_DN<0>")
	)
	(segment
		(start 317.961518 -231.034844)
		(end 317.961518 -230.858822)
		(width 0.18288)
		(layer "In4.Cu")
		(net "M_B_CPU0_SB_DQS_DN<0>")
	)
	(segment
		(start 335.428082 -235.294424)
		(end 335.41335 -235.285788)
		(width 0.088646)
		(layer "In4.Cu")
		(net "M_B_CPU0_SB_DQS_DN<0>")
	)
	(segment
		(start 296.83329 -227.820728)
		(end 296.28465 -227.820728)
		(width 0.18288)
		(layer "In4.Cu")
		(net "M_B_CPU0_SB_DQS_DN<0>")
	)
	(segment
		(start 316.445392 -229.518718)
		(end 315.516768 -228.590094)
		(width 0.18288)
		(layer "In4.Cu")
		(net "M_B_CPU0_SB_DQS_DN<0>")
	)
	(segment
		(start 303.525682 -227.722176)
		(end 303.401222 -227.846636)
		(width 0.18288)
		(layer "In4.Cu")
		(net "M_B_CPU0_SB_DQS_DN<0>")
	)
	(segment
		(start 332.091792 -235.218732)
		(end 332.020164 -235.29036)
		(width 0.088646)
		(layer "In4.Cu")
		(net "M_B_CPU0_SB_DQS_DN<0>")
	)
	(segment
		(start 330.746354 -235.29036)
		(end 330.686664 -235.23067)
		(width 0.088646)
		(layer "In4.Cu")
		(net "M_B_CPU0_SB_DQS_DN<0>")
	)
	(segment
		(start 334.488282 -235.294424)
		(end 334.47355 -235.285788)
		(width 0.088646)
		(layer "In4.Cu")
		(net "M_B_CPU0_SB_DQS_DN<0>")
	)
	(segment
		(start 312.755788 -228.023674)
		(end 312.367676 -227.635562)
		(width 0.18288)
		(layer "In4.Cu")
		(net "M_B_CPU0_SB_DQS_DN<0>")
	)
	(segment
		(start 318.525398 -231.422702)
		(end 318.349376 -231.422702)
		(width 0.18288)
		(layer "In4.Cu")
		(net "M_B_CPU0_SB_DQS_DN<0>")
	)
	(segment
		(start 321.769486 -234.66679)
		(end 321.381374 -234.278678)
		(width 0.18288)
		(layer "In4.Cu")
		(net "M_B_CPU0_SB_DQS_DN<0>")
	)
	(segment
		(start 330.648564 -235.23067)
		(end 322.157344 -235.23067)
		(width 0.18288)
		(layer "In4.Cu")
		(net "M_B_CPU0_SB_DQS_DN<0>")
	)
	(segment
		(start 306.745132 -226.648264)
		(end 306.180236 -226.648264)
		(width 0.18288)
		(layer "In4.Cu")
		(net "M_B_CPU0_SB_DQS_DN<0>")
	)
	(segment
		(start 308.458362 -226.259898)
		(end 307.133498 -226.259898)
		(width 0.18288)
		(layer "In4.Cu")
		(net "M_B_CPU0_SB_DQS_DN<0>")
	)
	(segment
		(start 310.44515 -226.901756)
		(end 310.185054 -226.64166)
		(width 0.18288)
		(layer "In4.Cu")
		(net "M_B_CPU0_SB_DQS_DN<0>")
	)
	(segment
		(start 298.78147 -228.341682)
		(end 298.477178 -228.645974)
		(width 0.18288)
		(layer "In4.Cu")
		(net "M_B_CPU0_SB_DQS_DN<0>")
	)
	(segment
		(start 313.143646 -228.587554)
		(end 312.755788 -228.199696)
		(width 0.18288)
		(layer "In4.Cu")
		(net "M_B_CPU0_SB_DQS_DN<0>")
	)
	(segment
		(start 338.875624 -235.148882)
		(end 338.622386 -235.294678)
		(width 0.088646)
		(layer "In4.Cu")
		(net "M_B_CPU0_SB_DQS_DN<0>")
	)
	(segment
		(start 301.011336 -228.341682)
		(end 298.78147 -228.341682)
		(width 0.18288)
		(layer "In4.Cu")
		(net "M_B_CPU0_SB_DQS_DN<0>")
	)
	(segment
		(start 311.457848 -226.901756)
		(end 310.44515 -226.901756)
		(width 0.18288)
		(layer "In4.Cu")
		(net "M_B_CPU0_SB_DQS_DN<0>")
	)
	(segment
		(start 310.185054 -226.64166)
		(end 309.793132 -226.64166)
		(width 0.18288)
		(layer "In4.Cu")
		(net "M_B_CPU0_SB_DQS_DN<0>")
	)
	(segment
		(start 339.34273 -235.08589)
		(end 339.303868 -235.107988)
		(width 0.088646)
		(layer "In4.Cu")
		(net "M_B_CPU0_SB_DQS_DN<0>")
	)
	(segment
		(start 320.817494 -233.89082)
		(end 320.817494 -233.714798)
		(width 0.18288)
		(layer "In4.Cu")
		(net "M_B_CPU0_SB_DQS_DN<0>")
	)
	(segment
		(start 338.622386 -235.294678)
		(end 338.622132 -235.294424)
		(width 0.088646)
		(layer "In4.Cu")
		(net "M_B_CPU0_SB_DQS_DN<0>")
	)
	(segment
		(start 319.865502 -232.938828)
		(end 319.865502 -232.762806)
		(width 0.18288)
		(layer "In4.Cu")
		(net "M_B_CPU0_SB_DQS_DN<0>")
	)
	(segment
		(start 314.532518 -228.590094)
		(end 314.287154 -228.34473)
		(width 0.18288)
		(layer "In4.Cu")
		(net "M_B_CPU0_SB_DQS_DN<0>")
	)
	(segment
		(start 309.527702 -226.90709)
		(end 309.105554 -226.90709)
		(width 0.18288)
		(layer "In4.Cu")
		(net "M_B_CPU0_SB_DQS_DN<0>")
	)
	(segment
		(start 302.852582 -227.846636)
		(end 302.728122 -227.722176)
		(width 0.18288)
		(layer "In4.Cu")
		(net "M_B_CPU0_SB_DQS_DN<0>")
	)
	(segment
		(start 295.61155 -227.945188)
		(end 295.381426 -228.175312)
		(width 0.18288)
		(layer "In4.Cu")
		(net "M_B_CPU0_SB_DQS_DN<0>")
	)
	(segment
		(start 338.247736 -235.294424)
		(end 338.237322 -235.288328)
		(width 0.088646)
		(layer "In4.Cu")
		(net "M_B_CPU0_SB_DQS_DN<0>")
	)
	(segment
		(start 312.755788 -228.199696)
		(end 312.755788 -228.023674)
		(width 0.18288)
		(layer "In4.Cu")
		(net "M_B_CPU0_SB_DQS_DN<0>")
	)
	(segment
		(start 319.47739 -232.374694)
		(end 319.301368 -232.374694)
		(width 0.18288)
		(layer "In4.Cu")
		(net "M_B_CPU0_SB_DQS_DN<0>")
	)
	(arc
		(start 336.35315 -235.285788)
		(mid 336.076675 -235.218468)
		(end 335.802478 -235.294424)
		(width 0.088646)
		(layer "In4.Cu")
		(net "M_B_CPU0_SB_DQS_DN<0>")
	)
	(arc
		(start 333.922878 -235.294424)
		(mid 333.73568 -235.344567)
		(end 333.548482 -235.294424)
		(width 0.088646)
		(layer "In4.Cu")
		(net "M_B_CPU0_SB_DQS_DN<0>")
	)
	(arc
		(start 334.47355 -235.285788)
		(mid 334.197075 -235.218468)
		(end 333.922878 -235.294424)
		(width 0.088646)
		(layer "In4.Cu")
		(net "M_B_CPU0_SB_DQS_DN<0>")
	)
	(arc
		(start 336.742278 -235.294424)
		(mid 336.55508 -235.344567)
		(end 336.367882 -235.294424)
		(width 0.088646)
		(layer "In4.Cu")
		(net "M_B_CPU0_SB_DQS_DN<0>")
	)
	(arc
		(start 332.983078 -235.294424)
		(mid 332.79588 -235.344567)
		(end 332.608682 -235.294424)
		(width 0.088646)
		(layer "In4.Cu")
		(net "M_B_CPU0_SB_DQS_DN<0>")
	)
	(arc
		(start 337.29295 -235.285788)
		(mid 337.016475 -235.218468)
		(end 336.742278 -235.294424)
		(width 0.088646)
		(layer "In4.Cu")
		(net "M_B_CPU0_SB_DQS_DN<0>")
	)
	(arc
		(start 335.802478 -235.294424)
		(mid 335.61528 -235.344567)
		(end 335.428082 -235.294424)
		(width 0.088646)
		(layer "In4.Cu")
		(net "M_B_CPU0_SB_DQS_DN<0>")
	)
	(arc
		(start 337.682078 -235.294424)
		(mid 337.49488 -235.344567)
		(end 337.307682 -235.294424)
		(width 0.088646)
		(layer "In4.Cu")
		(net "M_B_CPU0_SB_DQS_DN<0>")
	)
	(arc
		(start 339.303868 -235.107988)
		(mid 339.229183 -235.138493)
		(end 339.149182 -235.148882)
		(width 0.088646)
		(layer "In4.Cu")
		(net "M_B_CPU0_SB_DQS_DN<0>")
	)
	(arc
		(start 332.608682 -235.294424)
		(mid 332.472312 -235.237971)
		(end 332.32598 -235.218732)
		(width 0.088646)
		(layer "In4.Cu")
		(net "M_B_CPU0_SB_DQS_DN<0>")
	)
	(arc
		(start 338.622132 -235.294424)
		(mid 338.434934 -235.344567)
		(end 338.247736 -235.294424)
		(width 0.088646)
		(layer "In4.Cu")
		(net "M_B_CPU0_SB_DQS_DN<0>")
	)
	(arc
		(start 338.237322 -235.288328)
		(mid 337.95889 -235.218482)
		(end 337.682078 -235.294424)
		(width 0.088646)
		(layer "In4.Cu")
		(net "M_B_CPU0_SB_DQS_DN<0>")
	)
	(arc
		(start 333.53375 -235.285788)
		(mid 333.257275 -235.218468)
		(end 332.983078 -235.294424)
		(width 0.088646)
		(layer "In4.Cu")
		(net "M_B_CPU0_SB_DQS_DN<0>")
	)
	(arc
		(start 334.862678 -235.294424)
		(mid 334.67548 -235.344567)
		(end 334.488282 -235.294424)
		(width 0.088646)
		(layer "In4.Cu")
		(net "M_B_CPU0_SB_DQS_DN<0>")
	)
	(arc
		(start 335.41335 -235.285788)
		(mid 335.136875 -235.218468)
		(end 334.862678 -235.294424)
		(width 0.088646)
		(layer "In4.Cu")
		(net "M_B_CPU0_SB_DQS_DN<0>")
	)
	(segment
		(start 292.160198 -221.116652)
		(end 291.735256 -220.69171)
		(width 0.20066)
		(layer "F.Cu")
		(net "M_B_CPU0_SB_DQ<9>")
	)
	(segment
		(start 336.555334 -233.87812)
		(end 336.55508 -233.877866)
		(width 0.20066)
		(layer "F.Cu")
		(net "M_B_CPU0_SB_DQ<9>")
	)
	(segment
		(start 287.801304 -221.32798)
		(end 287.589976 -221.116652)
		(width 0.20066)
		(layer "F.Cu")
		(net "M_B_CPU0_SB_DQ<9>")
	)
	(segment
		(start 291.556694 -220.69171)
		(end 291.225986 -220.69171)
		(width 0.101854)
		(layer "F.Cu")
		(net "M_B_CPU0_SB_DQ<9>")
	)
	(segment
		(start 288.305748 -221.32798)
		(end 287.801304 -221.32798)
		(width 0.20066)
		(layer "F.Cu")
		(net "M_B_CPU0_SB_DQ<9>")
	)
	(segment
		(start 289.231578 -220.68282)
		(end 288.62274 -220.68282)
		(width 0.20066)
		(layer "F.Cu")
		(net "M_B_CPU0_SB_DQ<9>")
	)
	(segment
		(start 293.799514 -221.116652)
		(end 292.160198 -221.116652)
		(width 0.20066)
		(layer "F.Cu")
		(net "M_B_CPU0_SB_DQ<9>")
	)
	(segment
		(start 288.46018 -220.84538)
		(end 288.46018 -221.173548)
		(width 0.20066)
		(layer "F.Cu")
		(net "M_B_CPU0_SB_DQ<9>")
	)
	(segment
		(start 291.225986 -220.69171)
		(end 289.240468 -220.69171)
		(width 0.1016)
		(layer "F.Cu")
		(net "M_B_CPU0_SB_DQ<9>")
	)
	(segment
		(start 287.589976 -221.116652)
		(end 286.255714 -221.116652)
		(width 0.20066)
		(layer "F.Cu")
		(net "M_B_CPU0_SB_DQ<9>")
	)
	(segment
		(start 336.55508 -233.877866)
		(end 336.55508 -233.34218)
		(width 0.20066)
		(layer "F.Cu")
		(net "M_B_CPU0_SB_DQ<9>")
	)
	(segment
		(start 289.240468 -220.69171)
		(end 289.231578 -220.68282)
		(width 0.1016)
		(layer "F.Cu")
		(net "M_B_CPU0_SB_DQ<9>")
	)
	(segment
		(start 294.904414 -221.116652)
		(end 293.799514 -221.116652)
		(width 0.20066)
		(layer "F.Cu")
		(net "M_B_CPU0_SB_DQ<9>")
	)
	(segment
		(start 288.62274 -220.68282)
		(end 288.46018 -220.84538)
		(width 0.20066)
		(layer "F.Cu")
		(net "M_B_CPU0_SB_DQ<9>")
	)
	(segment
		(start 291.735256 -220.69171)
		(end 291.556694 -220.69171)
		(width 0.20066)
		(layer "F.Cu")
		(net "M_B_CPU0_SB_DQ<9>")
	)
	(segment
		(start 288.46018 -221.173548)
		(end 288.305748 -221.32798)
		(width 0.20066)
		(layer "F.Cu")
		(net "M_B_CPU0_SB_DQ<9>")
	)
	(segment
		(start 298.395136 -221.347792)
		(end 298.395136 -220.908372)
		(width 0.18288)
		(layer "In2.Cu")
		(net "M_B_CPU0_SB_DQ<9>")
	)
	(segment
		(start 298.235116 -220.748352)
		(end 297.68165 -220.748352)
		(width 0.18288)
		(layer "In2.Cu")
		(net "M_B_CPU0_SB_DQ<9>")
	)
	(segment
		(start 331.181964 -233.538776)
		(end 330.595986 -233.538776)
		(width 0.18288)
		(layer "In2.Cu")
		(net "M_B_CPU0_SB_DQ<9>")
	)
	(segment
		(start 334.018636 -233.831892)
		(end 334.008222 -233.837988)
		(width 0.088646)
		(layer "In2.Cu")
		(net "M_B_CPU0_SB_DQ<9>")
	)
	(segment
		(start 331.493368 -233.538776)
		(end 331.181964 -233.538776)
		(width 0.088646)
		(layer "In2.Cu")
		(net "M_B_CPU0_SB_DQ<9>")
	)
	(segment
		(start 336.55508 -233.34218)
		(end 336.554826 -233.342434)
		(width 0.088646)
		(layer "In2.Cu")
		(net "M_B_CPU0_SB_DQ<9>")
	)
	(segment
		(start 300.365668 -221.412054)
		(end 299.44949 -221.412054)
		(width 0.18288)
		(layer "In2.Cu")
		(net "M_B_CPU0_SB_DQ<9>")
	)
	(segment
		(start 303.903634 -222.34779)
		(end 302.925226 -221.369382)
		(width 0.18288)
		(layer "In2.Cu")
		(net "M_B_CPU0_SB_DQ<9>")
	)
	(segment
		(start 296.42435 -222.245174)
		(end 296.231056 -222.438468)
		(width 0.18288)
		(layer "In2.Cu")
		(net "M_B_CPU0_SB_DQ<9>")
	)
	(segment
		(start 307.723032 -221.49562)
		(end 306.870862 -222.34779)
		(width 0.18288)
		(layer "In2.Cu")
		(net "M_B_CPU0_SB_DQ<9>")
	)
	(segment
		(start 299.319696 -221.541848)
		(end 298.589192 -221.541848)
		(width 0.18288)
		(layer "In2.Cu")
		(net "M_B_CPU0_SB_DQ<9>")
	)
	(segment
		(start 295.54678 -221.309946)
		(end 295.353486 -221.116652)
		(width 0.18288)
		(layer "In2.Cu")
		(net "M_B_CPU0_SB_DQ<9>")
	)
	(segment
		(start 297.52163 -221.380558)
		(end 297.343576 -221.558612)
		(width 0.18288)
		(layer "In2.Cu")
		(net "M_B_CPU0_SB_DQ<9>")
	)
	(segment
		(start 302.077882 -221.577408)
		(end 300.531022 -221.577408)
		(width 0.18288)
		(layer "In2.Cu")
		(net "M_B_CPU0_SB_DQ<9>")
	)
	(segment
		(start 314.272676 -220.672152)
		(end 311.25668 -220.672152)
		(width 0.18288)
		(layer "In2.Cu")
		(net "M_B_CPU0_SB_DQ<9>")
	)
	(segment
		(start 296.61739 -221.558612)
		(end 296.42435 -221.751652)
		(width 0.18288)
		(layer "In2.Cu")
		(net "M_B_CPU0_SB_DQ<9>")
	)
	(segment
		(start 300.531022 -221.577408)
		(end 300.365668 -221.412054)
		(width 0.18288)
		(layer "In2.Cu")
		(net "M_B_CPU0_SB_DQ<9>")
	)
	(segment
		(start 311.25668 -220.672152)
		(end 310.433212 -221.49562)
		(width 0.18288)
		(layer "In2.Cu")
		(net "M_B_CPU0_SB_DQ<9>")
	)
	(segment
		(start 331.735684 -233.781092)
		(end 331.493368 -233.538776)
		(width 0.088646)
		(layer "In2.Cu")
		(net "M_B_CPU0_SB_DQ<9>")
	)
	(segment
		(start 318.072008 -221.014798)
		(end 317.798704 -221.014798)
		(width 0.18288)
		(layer "In2.Cu")
		(net "M_B_CPU0_SB_DQ<9>")
	)
	(segment
		(start 296.231056 -222.438468)
		(end 295.740074 -222.438468)
		(width 0.18288)
		(layer "In2.Cu")
		(net "M_B_CPU0_SB_DQ<9>")
	)
	(segment
		(start 310.433212 -221.49562)
		(end 307.723032 -221.49562)
		(width 0.18288)
		(layer "In2.Cu")
		(net "M_B_CPU0_SB_DQ<9>")
	)
	(segment
		(start 330.595986 -233.538776)
		(end 318.072008 -221.014798)
		(width 0.18288)
		(layer "In2.Cu")
		(net "M_B_CPU0_SB_DQ<9>")
	)
	(segment
		(start 295.353486 -221.116652)
		(end 294.904414 -221.116652)
		(width 0.18288)
		(layer "In2.Cu")
		(net "M_B_CPU0_SB_DQ<9>")
	)
	(segment
		(start 298.589192 -221.541848)
		(end 298.395136 -221.347792)
		(width 0.18288)
		(layer "In2.Cu")
		(net "M_B_CPU0_SB_DQ<9>")
	)
	(segment
		(start 297.52163 -220.908372)
		(end 297.52163 -221.380558)
		(width 0.18288)
		(layer "In2.Cu")
		(net "M_B_CPU0_SB_DQ<9>")
	)
	(segment
		(start 298.395136 -220.908372)
		(end 298.235116 -220.748352)
		(width 0.18288)
		(layer "In2.Cu")
		(net "M_B_CPU0_SB_DQ<9>")
	)
	(segment
		(start 306.870862 -222.34779)
		(end 303.903634 -222.34779)
		(width 0.18288)
		(layer "In2.Cu")
		(net "M_B_CPU0_SB_DQ<9>")
	)
	(segment
		(start 315.09462 -221.494096)
		(end 314.272676 -220.672152)
		(width 0.18288)
		(layer "In2.Cu")
		(net "M_B_CPU0_SB_DQ<9>")
	)
	(segment
		(start 302.285908 -221.369382)
		(end 302.077882 -221.577408)
		(width 0.18288)
		(layer "In2.Cu")
		(net "M_B_CPU0_SB_DQ<9>")
	)
	(segment
		(start 317.319406 -221.494096)
		(end 315.09462 -221.494096)
		(width 0.18288)
		(layer "In2.Cu")
		(net "M_B_CPU0_SB_DQ<9>")
	)
	(segment
		(start 317.798704 -221.014798)
		(end 317.319406 -221.494096)
		(width 0.18288)
		(layer "In2.Cu")
		(net "M_B_CPU0_SB_DQ<9>")
	)
	(segment
		(start 297.68165 -220.748352)
		(end 297.52163 -220.908372)
		(width 0.18288)
		(layer "In2.Cu")
		(net "M_B_CPU0_SB_DQ<9>")
	)
	(segment
		(start 332.326234 -233.781092)
		(end 331.735684 -233.781092)
		(width 0.088646)
		(layer "In2.Cu")
		(net "M_B_CPU0_SB_DQ<9>")
	)
	(segment
		(start 335.970372 -233.789982)
		(end 335.898236 -233.831892)
		(width 0.088646)
		(layer "In2.Cu")
		(net "M_B_CPU0_SB_DQ<9>")
	)
	(segment
		(start 302.925226 -221.369382)
		(end 302.285908 -221.369382)
		(width 0.18288)
		(layer "In2.Cu")
		(net "M_B_CPU0_SB_DQ<9>")
	)
	(segment
		(start 297.343576 -221.558612)
		(end 296.61739 -221.558612)
		(width 0.18288)
		(layer "In2.Cu")
		(net "M_B_CPU0_SB_DQ<9>")
	)
	(segment
		(start 296.42435 -221.751652)
		(end 296.42435 -222.245174)
		(width 0.18288)
		(layer "In2.Cu")
		(net "M_B_CPU0_SB_DQ<9>")
	)
	(segment
		(start 333.078582 -233.831892)
		(end 333.078836 -233.831892)
		(width 0.088646)
		(layer "In2.Cu")
		(net "M_B_CPU0_SB_DQ<9>")
	)
	(segment
		(start 295.740074 -222.438468)
		(end 295.54678 -222.245174)
		(width 0.18288)
		(layer "In2.Cu")
		(net "M_B_CPU0_SB_DQ<9>")
	)
	(segment
		(start 299.44949 -221.412054)
		(end 299.319696 -221.541848)
		(width 0.18288)
		(layer "In2.Cu")
		(net "M_B_CPU0_SB_DQ<9>")
	)
	(segment
		(start 295.54678 -222.245174)
		(end 295.54678 -221.309946)
		(width 0.18288)
		(layer "In2.Cu")
		(net "M_B_CPU0_SB_DQ<9>")
	)
	(arc
		(start 334.008222 -233.837988)
		(mid 333.72979 -233.907802)
		(end 333.452978 -233.831892)
		(width 0.088646)
		(layer "In2.Cu")
		(net "M_B_CPU0_SB_DQ<9>")
	)
	(arc
		(start 336.554826 -233.342434)
		(mid 336.277395 -233.585531)
		(end 335.970372 -233.789982)
		(width 0.088646)
		(layer "In2.Cu")
		(net "M_B_CPU0_SB_DQ<9>")
	)
	(arc
		(start 334.393032 -233.831892)
		(mid 334.205834 -233.781749)
		(end 334.018636 -233.831892)
		(width 0.088646)
		(layer "In2.Cu")
		(net "M_B_CPU0_SB_DQ<9>")
	)
	(arc
		(start 333.452978 -233.831892)
		(mid 333.26578 -233.781749)
		(end 333.078582 -233.831892)
		(width 0.088646)
		(layer "In2.Cu")
		(net "M_B_CPU0_SB_DQ<9>")
	)
	(arc
		(start 332.513432 -233.831892)
		(mid 332.423176 -233.79417)
		(end 332.326234 -233.781092)
		(width 0.088646)
		(layer "In2.Cu")
		(net "M_B_CPU0_SB_DQ<9>")
	)
	(arc
		(start 335.332832 -233.831892)
		(mid 335.145634 -233.781749)
		(end 334.958436 -233.831892)
		(width 0.088646)
		(layer "In2.Cu")
		(net "M_B_CPU0_SB_DQ<9>")
	)
	(arc
		(start 335.898236 -233.831892)
		(mid 335.615534 -233.907634)
		(end 335.332832 -233.831892)
		(width 0.088646)
		(layer "In2.Cu")
		(net "M_B_CPU0_SB_DQ<9>")
	)
	(arc
		(start 333.078836 -233.831892)
		(mid 332.796134 -233.907634)
		(end 332.513432 -233.831892)
		(width 0.088646)
		(layer "In2.Cu")
		(net "M_B_CPU0_SB_DQ<9>")
	)
	(arc
		(start 334.958436 -233.831892)
		(mid 334.675734 -233.907634)
		(end 334.393032 -233.831892)
		(width 0.088646)
		(layer "In2.Cu")
		(net "M_B_CPU0_SB_DQ<9>")
	)
	(segment
		(start 337.02498 -234.69219)
		(end 337.02498 -234.156504)
		(width 0.20066)
		(layer "F.Cu")
		(net "M_B_CPU0_SB_DQ<8>")
	)
	(segment
		(start 288.66973 -222.383604)
		(end 288.46018 -222.593154)
		(width 0.20066)
		(layer "F.Cu")
		(net "M_B_CPU0_SB_DQ<8>")
	)
	(segment
		(start 337.02498 -234.156504)
		(end 337.025234 -234.15625)
		(width 0.20066)
		(layer "F.Cu")
		(net "M_B_CPU0_SB_DQ<8>")
	)
	(segment
		(start 287.828736 -223.055434)
		(end 287.589976 -222.816674)
		(width 0.20066)
		(layer "F.Cu")
		(net "M_B_CPU0_SB_DQ<8>")
	)
	(segment
		(start 289.48761 -222.391732)
		(end 289.239706 -222.391732)
		(width 0.101854)
		(layer "F.Cu")
		(net "M_B_CPU0_SB_DQ<8>")
	)
	(segment
		(start 288.46018 -222.593154)
		(end 288.46018 -222.882714)
		(width 0.20066)
		(layer "F.Cu")
		(net "M_B_CPU0_SB_DQ<8>")
	)
	(segment
		(start 287.589976 -222.816674)
		(end 286.255714 -222.816674)
		(width 0.20066)
		(layer "F.Cu")
		(net "M_B_CPU0_SB_DQ<8>")
	)
	(segment
		(start 293.799514 -222.816674)
		(end 292.430454 -222.816674)
		(width 0.20066)
		(layer "F.Cu")
		(net "M_B_CPU0_SB_DQ<8>")
	)
	(segment
		(start 288.46018 -222.882714)
		(end 288.28746 -223.055434)
		(width 0.20066)
		(layer "F.Cu")
		(net "M_B_CPU0_SB_DQ<8>")
	)
	(segment
		(start 294.904414 -222.816674)
		(end 293.799514 -222.816674)
		(width 0.20066)
		(layer "F.Cu")
		(net "M_B_CPU0_SB_DQ<8>")
	)
	(segment
		(start 288.28746 -223.055434)
		(end 287.828736 -223.055434)
		(width 0.20066)
		(layer "F.Cu")
		(net "M_B_CPU0_SB_DQ<8>")
	)
	(segment
		(start 289.239706 -222.391732)
		(end 289.231578 -222.383604)
		(width 0.101854)
		(layer "F.Cu")
		(net "M_B_CPU0_SB_DQ<8>")
	)
	(segment
		(start 292.430454 -222.816674)
		(end 292.005512 -222.391732)
		(width 0.20066)
		(layer "F.Cu")
		(net "M_B_CPU0_SB_DQ<8>")
	)
	(segment
		(start 289.231578 -222.383604)
		(end 288.66973 -222.383604)
		(width 0.20066)
		(layer "F.Cu")
		(net "M_B_CPU0_SB_DQ<8>")
	)
	(segment
		(start 291.556694 -222.391732)
		(end 289.48761 -222.391732)
		(width 0.1016)
		(layer "F.Cu")
		(net "M_B_CPU0_SB_DQ<8>")
	)
	(segment
		(start 292.005512 -222.391732)
		(end 291.556694 -222.391732)
		(width 0.20066)
		(layer "F.Cu")
		(net "M_B_CPU0_SB_DQ<8>")
	)
	(segment
		(start 331.70622 -234.594908)
		(end 331.666342 -234.55503)
		(width 0.088646)
		(layer "In2.Cu")
		(net "M_B_CPU0_SB_DQ<8>")
	)
	(segment
		(start 308.020212 -224.09912)
		(end 307.538628 -224.09912)
		(width 0.18288)
		(layer "In2.Cu")
		(net "M_B_CPU0_SB_DQ<8>")
	)
	(segment
		(start 299.3517 -223.197166)
		(end 299.30725 -223.241616)
		(width 0.18288)
		(layer "In2.Cu")
		(net "M_B_CPU0_SB_DQ<8>")
	)
	(segment
		(start 306.31511 -224.023936)
		(end 306.11064 -224.228406)
		(width 0.18288)
		(layer "In2.Cu")
		(net "M_B_CPU0_SB_DQ<8>")
	)
	(segment
		(start 335.428082 -234.645708)
		(end 335.41335 -234.654344)
		(width 0.088646)
		(layer "In2.Cu")
		(net "M_B_CPU0_SB_DQ<8>")
	)
	(segment
		(start 301.356522 -224.048574)
		(end 301.046388 -223.73844)
		(width 0.18288)
		(layer "In2.Cu")
		(net "M_B_CPU0_SB_DQ<8>")
	)
	(segment
		(start 331.666342 -234.55503)
		(end 331.181964 -234.55503)
		(width 0.088646)
		(layer "In2.Cu")
		(net "M_B_CPU0_SB_DQ<8>")
	)
	(segment
		(start 296.407586 -224.18294)
		(end 296.214546 -224.37598)
		(width 0.18288)
		(layer "In2.Cu")
		(net "M_B_CPU0_SB_DQ<8>")
	)
	(segment
		(start 301.046388 -223.428052)
		(end 300.815502 -223.197166)
		(width 0.18288)
		(layer "In2.Cu")
		(net "M_B_CPU0_SB_DQ<8>")
	)
	(segment
		(start 330.151486 -234.55503)
		(end 318.171068 -222.574612)
		(width 0.18288)
		(layer "In2.Cu")
		(net "M_B_CPU0_SB_DQ<8>")
	)
	(segment
		(start 318.171068 -222.574612)
		(end 314.489846 -222.574612)
		(width 0.18288)
		(layer "In2.Cu")
		(net "M_B_CPU0_SB_DQ<8>")
	)
	(segment
		(start 331.181964 -234.55503)
		(end 330.151486 -234.55503)
		(width 0.18288)
		(layer "In2.Cu")
		(net "M_B_CPU0_SB_DQ<8>")
	)
	(segment
		(start 305.828954 -224.96272)
		(end 303.063148 -224.96272)
		(width 0.18288)
		(layer "In2.Cu")
		(net "M_B_CPU0_SB_DQ<8>")
	)
	(segment
		(start 314.489846 -222.574612)
		(end 314.281566 -222.366332)
		(width 0.18288)
		(layer "In2.Cu")
		(net "M_B_CPU0_SB_DQ<8>")
	)
	(segment
		(start 302.149002 -224.048574)
		(end 301.356522 -224.048574)
		(width 0.18288)
		(layer "In2.Cu")
		(net "M_B_CPU0_SB_DQ<8>")
	)
	(segment
		(start 307.538628 -224.09912)
		(end 307.463444 -224.023936)
		(width 0.18288)
		(layer "In2.Cu")
		(net "M_B_CPU0_SB_DQ<8>")
	)
	(segment
		(start 337.025234 -234.15625)
		(end 336.480912 -234.573572)
		(width 0.088646)
		(layer "In2.Cu")
		(net "M_B_CPU0_SB_DQ<8>")
	)
	(segment
		(start 310.71058 -223.71177)
		(end 310.193182 -223.194372)
		(width 0.18288)
		(layer "In2.Cu")
		(net "M_B_CPU0_SB_DQ<8>")
	)
	(segment
		(start 334.488282 -234.645708)
		(end 334.47355 -234.654344)
		(width 0.088646)
		(layer "In2.Cu")
		(net "M_B_CPU0_SB_DQ<8>")
	)
	(segment
		(start 311.64911 -223.71177)
		(end 310.71058 -223.71177)
		(width 0.18288)
		(layer "In2.Cu")
		(net "M_B_CPU0_SB_DQ<8>")
	)
	(segment
		(start 300.815502 -223.197166)
		(end 299.3517 -223.197166)
		(width 0.18288)
		(layer "In2.Cu")
		(net "M_B_CPU0_SB_DQ<8>")
	)
	(segment
		(start 336.367882 -234.645708)
		(end 336.35315 -234.654344)
		(width 0.088646)
		(layer "In2.Cu")
		(net "M_B_CPU0_SB_DQ<8>")
	)
	(segment
		(start 295.45407 -224.130616)
		(end 295.45407 -223.36633)
		(width 0.18288)
		(layer "In2.Cu")
		(net "M_B_CPU0_SB_DQ<8>")
	)
	(segment
		(start 310.193182 -223.194372)
		(end 308.92496 -223.194372)
		(width 0.18288)
		(layer "In2.Cu")
		(net "M_B_CPU0_SB_DQ<8>")
	)
	(segment
		(start 295.699434 -224.37598)
		(end 295.45407 -224.130616)
		(width 0.18288)
		(layer "In2.Cu")
		(net "M_B_CPU0_SB_DQ<8>")
	)
	(segment
		(start 296.214546 -224.37598)
		(end 295.699434 -224.37598)
		(width 0.18288)
		(layer "In2.Cu")
		(net "M_B_CPU0_SB_DQ<8>")
	)
	(segment
		(start 336.406998 -234.623102)
		(end 336.367882 -234.645708)
		(width 0.088646)
		(layer "In2.Cu")
		(net "M_B_CPU0_SB_DQ<8>")
	)
	(segment
		(start 296.407586 -223.750124)
		(end 296.407586 -224.18294)
		(width 0.18288)
		(layer "In2.Cu")
		(net "M_B_CPU0_SB_DQ<8>")
	)
	(segment
		(start 299.30725 -223.241616)
		(end 296.916094 -223.241616)
		(width 0.18288)
		(layer "In2.Cu")
		(net "M_B_CPU0_SB_DQ<8>")
	)
	(segment
		(start 295.45407 -223.36633)
		(end 294.904414 -222.816674)
		(width 0.18288)
		(layer "In2.Cu")
		(net "M_B_CPU0_SB_DQ<8>")
	)
	(segment
		(start 307.463444 -224.023936)
		(end 306.31511 -224.023936)
		(width 0.18288)
		(layer "In2.Cu")
		(net "M_B_CPU0_SB_DQ<8>")
	)
	(segment
		(start 333.548482 -234.645708)
		(end 333.53375 -234.654344)
		(width 0.088646)
		(layer "In2.Cu")
		(net "M_B_CPU0_SB_DQ<8>")
	)
	(segment
		(start 306.11064 -224.228406)
		(end 306.11064 -224.681034)
		(width 0.18288)
		(layer "In2.Cu")
		(net "M_B_CPU0_SB_DQ<8>")
	)
	(segment
		(start 314.281566 -222.366332)
		(end 312.994548 -222.366332)
		(width 0.18288)
		(layer "In2.Cu")
		(net "M_B_CPU0_SB_DQ<8>")
	)
	(segment
		(start 296.916094 -223.241616)
		(end 296.407586 -223.750124)
		(width 0.18288)
		(layer "In2.Cu")
		(net "M_B_CPU0_SB_DQ<8>")
	)
	(segment
		(start 331.85608 -234.594908)
		(end 331.70622 -234.594908)
		(width 0.088646)
		(layer "In2.Cu")
		(net "M_B_CPU0_SB_DQ<8>")
	)
	(segment
		(start 332.608682 -234.645708)
		(end 332.59395 -234.654344)
		(width 0.088646)
		(layer "In2.Cu")
		(net "M_B_CPU0_SB_DQ<8>")
	)
	(segment
		(start 306.11064 -224.681034)
		(end 305.828954 -224.96272)
		(width 0.18288)
		(layer "In2.Cu")
		(net "M_B_CPU0_SB_DQ<8>")
	)
	(segment
		(start 308.92496 -223.194372)
		(end 308.020212 -224.09912)
		(width 0.18288)
		(layer "In2.Cu")
		(net "M_B_CPU0_SB_DQ<8>")
	)
	(segment
		(start 303.063148 -224.96272)
		(end 302.149002 -224.048574)
		(width 0.18288)
		(layer "In2.Cu")
		(net "M_B_CPU0_SB_DQ<8>")
	)
	(segment
		(start 312.994548 -222.366332)
		(end 311.64911 -223.71177)
		(width 0.18288)
		(layer "In2.Cu")
		(net "M_B_CPU0_SB_DQ<8>")
	)
	(segment
		(start 301.046388 -223.73844)
		(end 301.046388 -223.428052)
		(width 0.18288)
		(layer "In2.Cu")
		(net "M_B_CPU0_SB_DQ<8>")
	)
	(arc
		(start 332.043278 -234.645708)
		(mid 331.953022 -234.607986)
		(end 331.85608 -234.594908)
		(width 0.088646)
		(layer "In2.Cu")
		(net "M_B_CPU0_SB_DQ<8>")
	)
	(arc
		(start 334.47355 -234.654344)
		(mid 334.197075 -234.721664)
		(end 333.922878 -234.645708)
		(width 0.088646)
		(layer "In2.Cu")
		(net "M_B_CPU0_SB_DQ<8>")
	)
	(arc
		(start 332.59395 -234.654344)
		(mid 332.317475 -234.721664)
		(end 332.043278 -234.645708)
		(width 0.088646)
		(layer "In2.Cu")
		(net "M_B_CPU0_SB_DQ<8>")
	)
	(arc
		(start 335.802478 -234.645708)
		(mid 335.61528 -234.595565)
		(end 335.428082 -234.645708)
		(width 0.088646)
		(layer "In2.Cu")
		(net "M_B_CPU0_SB_DQ<8>")
	)
	(arc
		(start 332.983078 -234.645708)
		(mid 332.79588 -234.595565)
		(end 332.608682 -234.645708)
		(width 0.088646)
		(layer "In2.Cu")
		(net "M_B_CPU0_SB_DQ<8>")
	)
	(arc
		(start 336.480912 -234.573572)
		(mid 336.444756 -234.599533)
		(end 336.406998 -234.623102)
		(width 0.088646)
		(layer "In2.Cu")
		(net "M_B_CPU0_SB_DQ<8>")
	)
	(arc
		(start 334.862678 -234.645708)
		(mid 334.67548 -234.595565)
		(end 334.488282 -234.645708)
		(width 0.088646)
		(layer "In2.Cu")
		(net "M_B_CPU0_SB_DQ<8>")
	)
	(arc
		(start 335.41335 -234.654344)
		(mid 335.136875 -234.721664)
		(end 334.862678 -234.645708)
		(width 0.088646)
		(layer "In2.Cu")
		(net "M_B_CPU0_SB_DQ<8>")
	)
	(arc
		(start 336.35315 -234.654344)
		(mid 336.076675 -234.721664)
		(end 335.802478 -234.645708)
		(width 0.088646)
		(layer "In2.Cu")
		(net "M_B_CPU0_SB_DQ<8>")
	)
	(arc
		(start 333.53375 -234.654344)
		(mid 333.257275 -234.721664)
		(end 332.983078 -234.645708)
		(width 0.088646)
		(layer "In2.Cu")
		(net "M_B_CPU0_SB_DQ<8>")
	)
	(arc
		(start 333.922878 -234.645708)
		(mid 333.73568 -234.595565)
		(end 333.548482 -234.645708)
		(width 0.088646)
		(layer "In2.Cu")
		(net "M_B_CPU0_SB_DQ<8>")
	)
	(segment
		(start 295.693846 -223.942402)
		(end 295.544748 -224.0915)
		(width 0.20066)
		(layer "F.Cu")
		(net "M_B_CPU0_SB_DQ<7>")
	)
	(segment
		(start 296.42943 -223.874076)
		(end 296.217594 -223.66224)
		(width 0.20066)
		(layer "F.Cu")
		(net "M_B_CPU0_SB_DQ<7>")
	)
	(segment
		(start 292.67531 -224.105724)
		(end 292.321488 -224.105724)
		(width 0.20066)
		(layer "F.Cu")
		(net "M_B_CPU0_SB_DQ<7>")
	)
	(segment
		(start 292.178994 -223.792542)
		(end 292.05301 -223.666558)
		(width 0.20066)
		(layer "F.Cu")
		(net "M_B_CPU0_SB_DQ<7>")
	)
	(segment
		(start 297.899582 -223.666558)
		(end 297.08348 -223.666558)
		(width 0.20066)
		(layer "F.Cu")
		(net "M_B_CPU0_SB_DQ<7>")
	)
	(segment
		(start 292.321488 -224.105724)
		(end 292.178994 -223.96323)
		(width 0.20066)
		(layer "F.Cu")
		(net "M_B_CPU0_SB_DQ<7>")
	)
	(segment
		(start 292.927532 -224.0915)
		(end 292.689534 -224.0915)
		(width 0.101854)
		(layer "F.Cu")
		(net "M_B_CPU0_SB_DQ<7>")
	)
	(segment
		(start 295.693846 -223.790764)
		(end 295.693846 -223.942402)
		(width 0.20066)
		(layer "F.Cu")
		(net "M_B_CPU0_SB_DQ<7>")
	)
	(segment
		(start 296.875962 -223.874076)
		(end 296.42943 -223.874076)
		(width 0.20066)
		(layer "F.Cu")
		(net "M_B_CPU0_SB_DQ<7>")
	)
	(segment
		(start 299.004482 -223.666558)
		(end 297.899582 -223.666558)
		(width 0.20066)
		(layer "F.Cu")
		(net "M_B_CPU0_SB_DQ<7>")
	)
	(segment
		(start 341.254334 -233.87812)
		(end 341.25408 -233.877866)
		(width 0.20066)
		(layer "F.Cu")
		(net "M_B_CPU0_SB_DQ<7>")
	)
	(segment
		(start 295.82237 -223.66224)
		(end 295.693846 -223.790764)
		(width 0.20066)
		(layer "F.Cu")
		(net "M_B_CPU0_SB_DQ<7>")
	)
	(segment
		(start 292.689534 -224.0915)
		(end 292.67531 -224.105724)
		(width 0.101854)
		(layer "F.Cu")
		(net "M_B_CPU0_SB_DQ<7>")
	)
	(segment
		(start 296.217594 -223.66224)
		(end 295.82237 -223.66224)
		(width 0.20066)
		(layer "F.Cu")
		(net "M_B_CPU0_SB_DQ<7>")
	)
	(segment
		(start 295.544748 -224.0915)
		(end 295.000426 -224.0915)
		(width 0.20066)
		(layer "F.Cu")
		(net "M_B_CPU0_SB_DQ<7>")
	)
	(segment
		(start 297.08348 -223.666558)
		(end 296.875962 -223.874076)
		(width 0.20066)
		(layer "F.Cu")
		(net "M_B_CPU0_SB_DQ<7>")
	)
	(segment
		(start 341.25408 -233.877866)
		(end 341.25408 -233.34218)
		(width 0.20066)
		(layer "F.Cu")
		(net "M_B_CPU0_SB_DQ<7>")
	)
	(segment
		(start 295.000426 -224.0915)
		(end 292.927532 -224.0915)
		(width 0.1016)
		(layer "F.Cu")
		(net "M_B_CPU0_SB_DQ<7>")
	)
	(segment
		(start 292.05301 -223.666558)
		(end 290.355782 -223.666558)
		(width 0.20066)
		(layer "F.Cu")
		(net "M_B_CPU0_SB_DQ<7>")
	)
	(segment
		(start 292.178994 -223.96323)
		(end 292.178994 -223.792542)
		(width 0.20066)
		(layer "F.Cu")
		(net "M_B_CPU0_SB_DQ<7>")
	)
	(segment
		(start 307.03393 -220.49359)
		(end 306.03063 -220.49359)
		(width 0.18288)
		(layer "In4.Cu")
		(net "M_B_CPU0_SB_DQ<7>")
	)
	(segment
		(start 301.350934 -221.842584)
		(end 301.025814 -221.842584)
		(width 0.18288)
		(layer "In4.Cu")
		(net "M_B_CPU0_SB_DQ<7>")
	)
	(segment
		(start 312.681112 -220.642434)
		(end 310.865774 -220.642434)
		(width 0.18288)
		(layer "In4.Cu")
		(net "M_B_CPU0_SB_DQ<7>")
	)
	(segment
		(start 310.865774 -220.642434)
		(end 310.692038 -220.81617)
		(width 0.18288)
		(layer "In4.Cu")
		(net "M_B_CPU0_SB_DQ<7>")
	)
	(segment
		(start 300.842934 -222.025464)
		(end 300.842934 -222.960946)
		(width 0.18288)
		(layer "In4.Cu")
		(net "M_B_CPU0_SB_DQ<7>")
	)
	(segment
		(start 301.025814 -221.842584)
		(end 300.842934 -222.025464)
		(width 0.18288)
		(layer "In4.Cu")
		(net "M_B_CPU0_SB_DQ<7>")
	)
	(segment
		(start 334.018636 -232.852722)
		(end 334.008222 -232.846626)
		(width 0.088646)
		(layer "In4.Cu")
		(net "M_B_CPU0_SB_DQ<7>")
	)
	(segment
		(start 331.619098 -232.77703)
		(end 331.273658 -232.43159)
		(width 0.088646)
		(layer "In4.Cu")
		(net "M_B_CPU0_SB_DQ<7>")
	)
	(segment
		(start 310.692038 -220.81617)
		(end 307.35651 -220.81617)
		(width 0.18288)
		(layer "In4.Cu")
		(net "M_B_CPU0_SB_DQ<7>")
	)
	(segment
		(start 303.424082 -221.696788)
		(end 303.264062 -221.856808)
		(width 0.18288)
		(layer "In4.Cu")
		(net "M_B_CPU0_SB_DQ<7>")
	)
	(segment
		(start 301.716694 -223.143826)
		(end 301.533814 -222.960946)
		(width 0.18288)
		(layer "In4.Cu")
		(net "M_B_CPU0_SB_DQ<7>")
	)
	(segment
		(start 335.897982 -232.852722)
		(end 335.898236 -232.852722)
		(width 0.088646)
		(layer "In4.Cu")
		(net "M_B_CPU0_SB_DQ<7>")
	)
	(segment
		(start 314.255658 -220.642434)
		(end 313.658504 -220.642434)
		(width 0.18288)
		(layer "In4.Cu")
		(net "M_B_CPU0_SB_DQ<7>")
	)
	(segment
		(start 306.03063 -220.49359)
		(end 304.827432 -221.696788)
		(width 0.18288)
		(layer "In4.Cu")
		(net "M_B_CPU0_SB_DQ<7>")
	)
	(segment
		(start 341.25408 -233.34218)
		(end 340.624668 -232.951528)
		(width 0.088646)
		(layer "In4.Cu")
		(net "M_B_CPU0_SB_DQ<7>")
	)
	(segment
		(start 301.533814 -222.960946)
		(end 301.533814 -222.025464)
		(width 0.18288)
		(layer "In4.Cu")
		(net "M_B_CPU0_SB_DQ<7>")
	)
	(segment
		(start 338.723224 -232.856024)
		(end 338.71154 -232.84942)
		(width 0.088646)
		(layer "In4.Cu")
		(net "M_B_CPU0_SB_DQ<7>")
	)
	(segment
		(start 330.648564 -232.43159)
		(end 324.122034 -232.43159)
		(width 0.18288)
		(layer "In4.Cu")
		(net "M_B_CPU0_SB_DQ<7>")
	)
	(segment
		(start 304.827432 -221.696788)
		(end 303.424082 -221.696788)
		(width 0.18288)
		(layer "In4.Cu")
		(net "M_B_CPU0_SB_DQ<7>")
	)
	(segment
		(start 331.856334 -232.77703)
		(end 331.619098 -232.77703)
		(width 0.088646)
		(layer "In4.Cu")
		(net "M_B_CPU0_SB_DQ<7>")
	)
	(segment
		(start 324.122034 -232.43159)
		(end 316.048136 -224.357692)
		(width 0.18288)
		(layer "In4.Cu")
		(net "M_B_CPU0_SB_DQ<7>")
	)
	(segment
		(start 307.35651 -220.81617)
		(end 307.03393 -220.49359)
		(width 0.18288)
		(layer "In4.Cu")
		(net "M_B_CPU0_SB_DQ<7>")
	)
	(segment
		(start 316.048136 -224.357692)
		(end 314.688474 -221.07525)
		(width 0.18288)
		(layer "In4.Cu")
		(net "M_B_CPU0_SB_DQ<7>")
	)
	(segment
		(start 312.990484 -220.951806)
		(end 312.681112 -220.642434)
		(width 0.18288)
		(layer "In4.Cu")
		(net "M_B_CPU0_SB_DQ<7>")
	)
	(segment
		(start 333.078582 -232.852722)
		(end 333.06385 -232.844086)
		(width 0.088646)
		(layer "In4.Cu")
		(net "M_B_CPU0_SB_DQ<7>")
	)
	(segment
		(start 300.842934 -222.960946)
		(end 300.660054 -223.143826)
		(width 0.18288)
		(layer "In4.Cu")
		(net "M_B_CPU0_SB_DQ<7>")
	)
	(segment
		(start 331.273658 -232.43159)
		(end 330.648564 -232.43159)
		(width 0.088646)
		(layer "In4.Cu")
		(net "M_B_CPU0_SB_DQ<7>")
	)
	(segment
		(start 313.658504 -220.642434)
		(end 313.349132 -220.951806)
		(width 0.18288)
		(layer "In4.Cu")
		(net "M_B_CPU0_SB_DQ<7>")
	)
	(segment
		(start 337.783424 -232.856024)
		(end 337.77174 -232.84942)
		(width 0.088646)
		(layer "In4.Cu")
		(net "M_B_CPU0_SB_DQ<7>")
	)
	(segment
		(start 302.918114 -223.143826)
		(end 301.716694 -223.143826)
		(width 0.18288)
		(layer "In4.Cu")
		(net "M_B_CPU0_SB_DQ<7>")
	)
	(segment
		(start 314.688474 -221.07525)
		(end 314.255658 -220.642434)
		(width 0.18288)
		(layer "In4.Cu")
		(net "M_B_CPU0_SB_DQ<7>")
	)
	(segment
		(start 339.663024 -232.856024)
		(end 339.65134 -232.84942)
		(width 0.088646)
		(layer "In4.Cu")
		(net "M_B_CPU0_SB_DQ<7>")
	)
	(segment
		(start 313.349132 -220.951806)
		(end 312.990484 -220.951806)
		(width 0.18288)
		(layer "In4.Cu")
		(net "M_B_CPU0_SB_DQ<7>")
	)
	(segment
		(start 303.264062 -222.797878)
		(end 302.918114 -223.143826)
		(width 0.18288)
		(layer "In4.Cu")
		(net "M_B_CPU0_SB_DQ<7>")
	)
	(segment
		(start 336.843624 -232.856024)
		(end 336.83321 -232.850182)
		(width 0.088646)
		(layer "In4.Cu")
		(net "M_B_CPU0_SB_DQ<7>")
	)
	(segment
		(start 301.533814 -222.025464)
		(end 301.350934 -221.842584)
		(width 0.18288)
		(layer "In4.Cu")
		(net "M_B_CPU0_SB_DQ<7>")
	)
	(segment
		(start 299.527214 -223.143826)
		(end 299.004482 -223.666558)
		(width 0.18288)
		(layer "In4.Cu")
		(net "M_B_CPU0_SB_DQ<7>")
	)
	(segment
		(start 303.264062 -221.856808)
		(end 303.264062 -222.797878)
		(width 0.18288)
		(layer "In4.Cu")
		(net "M_B_CPU0_SB_DQ<7>")
	)
	(segment
		(start 300.660054 -223.143826)
		(end 299.527214 -223.143826)
		(width 0.18288)
		(layer "In4.Cu")
		(net "M_B_CPU0_SB_DQ<7>")
	)
	(arc
		(start 334.393032 -232.852722)
		(mid 334.205834 -232.902865)
		(end 334.018636 -232.852722)
		(width 0.088646)
		(layer "In4.Cu")
		(net "M_B_CPU0_SB_DQ<7>")
	)
	(arc
		(start 339.65134 -232.84942)
		(mid 339.371235 -232.776978)
		(end 339.092032 -232.852722)
		(width 0.088646)
		(layer "In4.Cu")
		(net "M_B_CPU0_SB_DQ<7>")
	)
	(arc
		(start 340.031832 -232.852722)
		(mid 339.847878 -232.902851)
		(end 339.663024 -232.856024)
		(width 0.088646)
		(layer "In4.Cu")
		(net "M_B_CPU0_SB_DQ<7>")
	)
	(arc
		(start 334.958436 -232.852722)
		(mid 334.675734 -232.776946)
		(end 334.393032 -232.852722)
		(width 0.088646)
		(layer "In4.Cu")
		(net "M_B_CPU0_SB_DQ<7>")
	)
	(arc
		(start 336.272632 -232.852722)
		(mid 336.085324 -232.902865)
		(end 335.897982 -232.852722)
		(width 0.088646)
		(layer "In4.Cu")
		(net "M_B_CPU0_SB_DQ<7>")
	)
	(arc
		(start 340.552786 -232.89895)
		(mid 340.299617 -232.793506)
		(end 340.031832 -232.852722)
		(width 0.088646)
		(layer "In4.Cu")
		(net "M_B_CPU0_SB_DQ<7>")
	)
	(arc
		(start 335.898236 -232.852722)
		(mid 335.615534 -232.776946)
		(end 335.332832 -232.852722)
		(width 0.088646)
		(layer "In4.Cu")
		(net "M_B_CPU0_SB_DQ<7>")
	)
	(arc
		(start 339.092032 -232.852722)
		(mid 338.908078 -232.902851)
		(end 338.723224 -232.856024)
		(width 0.088646)
		(layer "In4.Cu")
		(net "M_B_CPU0_SB_DQ<7>")
	)
	(arc
		(start 333.452978 -232.852722)
		(mid 333.26578 -232.902865)
		(end 333.078582 -232.852722)
		(width 0.088646)
		(layer "In4.Cu")
		(net "M_B_CPU0_SB_DQ<7>")
	)
	(arc
		(start 340.624668 -232.951528)
		(mid 340.587765 -232.926554)
		(end 340.552786 -232.89895)
		(width 0.088646)
		(layer "In4.Cu")
		(net "M_B_CPU0_SB_DQ<7>")
	)
	(arc
		(start 336.83321 -232.850182)
		(mid 336.552575 -232.777014)
		(end 336.272632 -232.852722)
		(width 0.088646)
		(layer "In4.Cu")
		(net "M_B_CPU0_SB_DQ<7>")
	)
	(arc
		(start 338.71154 -232.84942)
		(mid 338.431435 -232.776978)
		(end 338.152232 -232.852722)
		(width 0.088646)
		(layer "In4.Cu")
		(net "M_B_CPU0_SB_DQ<7>")
	)
	(arc
		(start 332.138782 -232.852722)
		(mid 332.00254 -232.796288)
		(end 331.856334 -232.77703)
		(width 0.088646)
		(layer "In4.Cu")
		(net "M_B_CPU0_SB_DQ<7>")
	)
	(arc
		(start 333.06385 -232.844086)
		(mid 332.787375 -232.776766)
		(end 332.513178 -232.852722)
		(width 0.088646)
		(layer "In4.Cu")
		(net "M_B_CPU0_SB_DQ<7>")
	)
	(arc
		(start 335.332832 -232.852722)
		(mid 335.145634 -232.902865)
		(end 334.958436 -232.852722)
		(width 0.088646)
		(layer "In4.Cu")
		(net "M_B_CPU0_SB_DQ<7>")
	)
	(arc
		(start 337.212432 -232.852722)
		(mid 337.028478 -232.902851)
		(end 336.843624 -232.856024)
		(width 0.088646)
		(layer "In4.Cu")
		(net "M_B_CPU0_SB_DQ<7>")
	)
	(arc
		(start 332.513178 -232.852722)
		(mid 332.32598 -232.902865)
		(end 332.138782 -232.852722)
		(width 0.088646)
		(layer "In4.Cu")
		(net "M_B_CPU0_SB_DQ<7>")
	)
	(arc
		(start 337.77174 -232.84942)
		(mid 337.491635 -232.776978)
		(end 337.212432 -232.852722)
		(width 0.088646)
		(layer "In4.Cu")
		(net "M_B_CPU0_SB_DQ<7>")
	)
	(arc
		(start 338.152232 -232.852722)
		(mid 337.968278 -232.902851)
		(end 337.783424 -232.856024)
		(width 0.088646)
		(layer "In4.Cu")
		(net "M_B_CPU0_SB_DQ<7>")
	)
	(arc
		(start 334.008222 -232.846626)
		(mid 333.72979 -232.77678)
		(end 333.452978 -232.852722)
		(width 0.088646)
		(layer "In4.Cu")
		(net "M_B_CPU0_SB_DQ<7>")
	)
	(segment
		(start 341.72398 -234.69219)
		(end 341.724234 -234.691936)
		(width 0.20066)
		(layer "F.Cu")
		(net "M_B_CPU0_SB_DQ<6>")
	)
	(segment
		(start 296.584878 -225.36658)
		(end 296.373042 -225.578416)
		(width 0.20066)
		(layer "F.Cu")
		(net "M_B_CPU0_SB_DQ<6>")
	)
	(segment
		(start 295.000426 -224.941638)
		(end 292.940486 -224.941638)
		(width 0.1016)
		(layer "F.Cu")
		(net "M_B_CPU0_SB_DQ<6>")
	)
	(segment
		(start 292.67531 -224.931478)
		(end 291.937948 -224.931478)
		(width 0.20066)
		(layer "F.Cu")
		(net "M_B_CPU0_SB_DQ<6>")
	)
	(segment
		(start 295.777158 -225.085402)
		(end 295.633394 -224.941638)
		(width 0.20066)
		(layer "F.Cu")
		(net "M_B_CPU0_SB_DQ<6>")
	)
	(segment
		(start 292.940486 -224.941638)
		(end 292.68547 -224.941638)
		(width 0.101854)
		(layer "F.Cu")
		(net "M_B_CPU0_SB_DQ<6>")
	)
	(segment
		(start 291.937948 -224.931478)
		(end 291.502846 -225.36658)
		(width 0.20066)
		(layer "F.Cu")
		(net "M_B_CPU0_SB_DQ<6>")
	)
	(segment
		(start 341.724234 -234.691936)
		(end 341.724234 -234.15625)
		(width 0.20066)
		(layer "F.Cu")
		(net "M_B_CPU0_SB_DQ<6>")
	)
	(segment
		(start 299.004482 -225.36658)
		(end 297.899582 -225.36658)
		(width 0.20066)
		(layer "F.Cu")
		(net "M_B_CPU0_SB_DQ<6>")
	)
	(segment
		(start 297.899582 -225.36658)
		(end 296.584878 -225.36658)
		(width 0.20066)
		(layer "F.Cu")
		(net "M_B_CPU0_SB_DQ<6>")
	)
	(segment
		(start 295.777158 -225.41103)
		(end 295.777158 -225.085402)
		(width 0.20066)
		(layer "F.Cu")
		(net "M_B_CPU0_SB_DQ<6>")
	)
	(segment
		(start 295.944544 -225.578416)
		(end 295.777158 -225.41103)
		(width 0.20066)
		(layer "F.Cu")
		(net "M_B_CPU0_SB_DQ<6>")
	)
	(segment
		(start 291.502846 -225.36658)
		(end 290.355782 -225.36658)
		(width 0.20066)
		(layer "F.Cu")
		(net "M_B_CPU0_SB_DQ<6>")
	)
	(segment
		(start 292.68547 -224.941638)
		(end 292.67531 -224.931478)
		(width 0.101854)
		(layer "F.Cu")
		(net "M_B_CPU0_SB_DQ<6>")
	)
	(segment
		(start 296.373042 -225.578416)
		(end 295.944544 -225.578416)
		(width 0.20066)
		(layer "F.Cu")
		(net "M_B_CPU0_SB_DQ<6>")
	)
	(segment
		(start 295.633394 -224.941638)
		(end 295.000426 -224.941638)
		(width 0.20066)
		(layer "F.Cu")
		(net "M_B_CPU0_SB_DQ<6>")
	)
	(segment
		(start 308.70398 -221.81312)
		(end 308.5211 -221.996)
		(width 0.18288)
		(layer "In4.Cu")
		(net "M_B_CPU0_SB_DQ<6>")
	)
	(segment
		(start 305.767994 -223.296226)
		(end 305.197256 -223.866964)
		(width 0.18288)
		(layer "In4.Cu")
		(net "M_B_CPU0_SB_DQ<6>")
	)
	(segment
		(start 301.347632 -225.312986)
		(end 301.022512 -225.312986)
		(width 0.18288)
		(layer "In4.Cu")
		(net "M_B_CPU0_SB_DQ<6>")
	)
	(segment
		(start 307.430932 -222.556832)
		(end 306.691538 -223.296226)
		(width 0.18288)
		(layer "In4.Cu")
		(net "M_B_CPU0_SB_DQ<6>")
	)
	(segment
		(start 339.569298 -233.662474)
		(end 339.561932 -233.666792)
		(width 0.088646)
		(layer "In4.Cu")
		(net "M_B_CPU0_SB_DQ<6>")
	)
	(segment
		(start 337.689698 -233.662474)
		(end 337.67776 -233.669332)
		(width 0.088646)
		(layer "In4.Cu")
		(net "M_B_CPU0_SB_DQ<6>")
	)
	(segment
		(start 314.496196 -223.40951)
		(end 314.247276 -223.24314)
		(width 0.18288)
		(layer "In4.Cu")
		(net "M_B_CPU0_SB_DQ<6>")
	)
	(segment
		(start 305.197256 -223.866964)
		(end 304.028856 -223.866964)
		(width 0.18288)
		(layer "In4.Cu")
		(net "M_B_CPU0_SB_DQ<6>")
	)
	(segment
		(start 314.247276 -223.24314)
		(end 313.755532 -223.24314)
		(width 0.18288)
		(layer "In4.Cu")
		(net "M_B_CPU0_SB_DQ<6>")
	)
	(segment
		(start 301.022512 -225.312986)
		(end 300.839632 -225.130106)
		(width 0.18288)
		(layer "In4.Cu")
		(net "M_B_CPU0_SB_DQ<6>")
	)
	(segment
		(start 315.140086 -224.962974)
		(end 314.496196 -223.40951)
		(width 0.18288)
		(layer "In4.Cu")
		(net "M_B_CPU0_SB_DQ<6>")
	)
	(segment
		(start 300.656752 -224.72015)
		(end 299.650912 -224.72015)
		(width 0.18288)
		(layer "In4.Cu")
		(net "M_B_CPU0_SB_DQ<6>")
	)
	(segment
		(start 301.713392 -224.72015)
		(end 301.530512 -224.90303)
		(width 0.18288)
		(layer "In4.Cu")
		(net "M_B_CPU0_SB_DQ<6>")
	)
	(segment
		(start 312.001662 -222.305626)
		(end 311.546748 -222.305626)
		(width 0.18288)
		(layer "In4.Cu")
		(net "M_B_CPU0_SB_DQ<6>")
	)
	(segment
		(start 303.17567 -224.72015)
		(end 301.713392 -224.72015)
		(width 0.18288)
		(layer "In4.Cu")
		(net "M_B_CPU0_SB_DQ<6>")
	)
	(segment
		(start 308.5211 -222.373952)
		(end 308.33822 -222.556832)
		(width 0.18288)
		(layer "In4.Cu")
		(net "M_B_CPU0_SB_DQ<6>")
	)
	(segment
		(start 311.546748 -222.305626)
		(end 311.295542 -222.556832)
		(width 0.18288)
		(layer "In4.Cu")
		(net "M_B_CPU0_SB_DQ<6>")
	)
	(segment
		(start 304.028856 -223.866964)
		(end 303.17567 -224.72015)
		(width 0.18288)
		(layer "In4.Cu")
		(net "M_B_CPU0_SB_DQ<6>")
	)
	(segment
		(start 341.724234 -234.15625)
		(end 341.18042 -233.738928)
		(width 0.088646)
		(layer "In4.Cu")
		(net "M_B_CPU0_SB_DQ<6>")
	)
	(segment
		(start 339.561932 -233.666792)
		(end 339.55736 -233.669332)
		(width 0.088646)
		(layer "In4.Cu")
		(net "M_B_CPU0_SB_DQ<6>")
	)
	(segment
		(start 312.656474 -222.264732)
		(end 312.569352 -222.4278)
		(width 0.18288)
		(layer "In4.Cu")
		(net "M_B_CPU0_SB_DQ<6>")
	)
	(segment
		(start 301.530512 -224.90303)
		(end 301.530512 -225.130106)
		(width 0.18288)
		(layer "In4.Cu")
		(net "M_B_CPU0_SB_DQ<6>")
	)
	(segment
		(start 313.267852 -222.59163)
		(end 313.20232 -222.375476)
		(width 0.18288)
		(layer "In4.Cu")
		(net "M_B_CPU0_SB_DQ<6>")
	)
	(segment
		(start 301.530512 -225.130106)
		(end 301.347632 -225.312986)
		(width 0.18288)
		(layer "In4.Cu")
		(net "M_B_CPU0_SB_DQ<6>")
	)
	(segment
		(start 311.295542 -222.556832)
		(end 309.39486 -222.556832)
		(width 0.18288)
		(layer "In4.Cu")
		(net "M_B_CPU0_SB_DQ<6>")
	)
	(segment
		(start 336.742532 -233.666792)
		(end 336.738722 -233.668824)
		(width 0.088646)
		(layer "In4.Cu")
		(net "M_B_CPU0_SB_DQ<6>")
	)
	(segment
		(start 309.39486 -222.556832)
		(end 309.21198 -222.373952)
		(width 0.18288)
		(layer "In4.Cu")
		(net "M_B_CPU0_SB_DQ<6>")
	)
	(segment
		(start 313.755532 -223.24314)
		(end 313.246516 -222.971106)
		(width 0.18288)
		(layer "In4.Cu")
		(net "M_B_CPU0_SB_DQ<6>")
	)
	(segment
		(start 309.21198 -222.373952)
		(end 309.21198 -221.996)
		(width 0.18288)
		(layer "In4.Cu")
		(net "M_B_CPU0_SB_DQ<6>")
	)
	(segment
		(start 300.839632 -225.130106)
		(end 300.839632 -224.90303)
		(width 0.18288)
		(layer "In4.Cu")
		(net "M_B_CPU0_SB_DQ<6>")
	)
	(segment
		(start 313.18073 -222.754698)
		(end 313.267852 -222.59163)
		(width 0.18288)
		(layer "In4.Cu")
		(net "M_B_CPU0_SB_DQ<6>")
	)
	(segment
		(start 312.872628 -222.1992)
		(end 312.656474 -222.264732)
		(width 0.18288)
		(layer "In4.Cu")
		(net "M_B_CPU0_SB_DQ<6>")
	)
	(segment
		(start 336.749898 -233.662474)
		(end 336.742532 -233.666792)
		(width 0.088646)
		(layer "In4.Cu")
		(net "M_B_CPU0_SB_DQ<6>")
	)
	(segment
		(start 323.604382 -233.42727)
		(end 315.140086 -224.962974)
		(width 0.18288)
		(layer "In4.Cu")
		(net "M_B_CPU0_SB_DQ<6>")
	)
	(segment
		(start 338.622132 -233.666792)
		(end 338.61756 -233.669332)
		(width 0.088646)
		(layer "In4.Cu")
		(net "M_B_CPU0_SB_DQ<6>")
	)
	(segment
		(start 331.51572 -233.845608)
		(end 331.097382 -233.42727)
		(width 0.088646)
		(layer "In4.Cu")
		(net "M_B_CPU0_SB_DQ<6>")
	)
	(segment
		(start 308.5211 -221.996)
		(end 308.5211 -222.373952)
		(width 0.18288)
		(layer "In4.Cu")
		(net "M_B_CPU0_SB_DQ<6>")
	)
	(segment
		(start 313.246516 -222.971106)
		(end 313.18073 -222.754698)
		(width 0.18288)
		(layer "In4.Cu")
		(net "M_B_CPU0_SB_DQ<6>")
	)
	(segment
		(start 331.926438 -233.756454)
		(end 331.837284 -233.845608)
		(width 0.088646)
		(layer "In4.Cu")
		(net "M_B_CPU0_SB_DQ<6>")
	)
	(segment
		(start 336.367882 -233.666792)
		(end 336.367882 -233.666538)
		(width 0.088646)
		(layer "In4.Cu")
		(net "M_B_CPU0_SB_DQ<6>")
	)
	(segment
		(start 338.629498 -233.662474)
		(end 338.622132 -233.666792)
		(width 0.088646)
		(layer "In4.Cu")
		(net "M_B_CPU0_SB_DQ<6>")
	)
	(segment
		(start 331.837284 -233.845608)
		(end 331.51572 -233.845608)
		(width 0.088646)
		(layer "In4.Cu")
		(net "M_B_CPU0_SB_DQ<6>")
	)
	(segment
		(start 312.352944 -222.493332)
		(end 312.001662 -222.305626)
		(width 0.18288)
		(layer "In4.Cu")
		(net "M_B_CPU0_SB_DQ<6>")
	)
	(segment
		(start 299.650912 -224.72015)
		(end 299.004482 -225.36658)
		(width 0.18288)
		(layer "In4.Cu")
		(net "M_B_CPU0_SB_DQ<6>")
	)
	(segment
		(start 330.648564 -233.42727)
		(end 323.604382 -233.42727)
		(width 0.18288)
		(layer "In4.Cu")
		(net "M_B_CPU0_SB_DQ<6>")
	)
	(segment
		(start 312.569352 -222.4278)
		(end 312.352944 -222.493332)
		(width 0.18288)
		(layer "In4.Cu")
		(net "M_B_CPU0_SB_DQ<6>")
	)
	(segment
		(start 300.839632 -224.90303)
		(end 300.656752 -224.72015)
		(width 0.18288)
		(layer "In4.Cu")
		(net "M_B_CPU0_SB_DQ<6>")
	)
	(segment
		(start 306.691538 -223.296226)
		(end 305.767994 -223.296226)
		(width 0.18288)
		(layer "In4.Cu")
		(net "M_B_CPU0_SB_DQ<6>")
	)
	(segment
		(start 309.21198 -221.996)
		(end 309.0291 -221.81312)
		(width 0.18288)
		(layer "In4.Cu")
		(net "M_B_CPU0_SB_DQ<6>")
	)
	(segment
		(start 331.097382 -233.42727)
		(end 330.648564 -233.42727)
		(width 0.088646)
		(layer "In4.Cu")
		(net "M_B_CPU0_SB_DQ<6>")
	)
	(segment
		(start 313.20232 -222.375476)
		(end 312.872628 -222.1992)
		(width 0.18288)
		(layer "In4.Cu")
		(net "M_B_CPU0_SB_DQ<6>")
	)
	(segment
		(start 308.33822 -222.556832)
		(end 307.430932 -222.556832)
		(width 0.18288)
		(layer "In4.Cu")
		(net "M_B_CPU0_SB_DQ<6>")
	)
	(segment
		(start 309.0291 -221.81312)
		(end 308.70398 -221.81312)
		(width 0.18288)
		(layer "In4.Cu")
		(net "M_B_CPU0_SB_DQ<6>")
	)
	(segment
		(start 336.367882 -233.666538)
		(end 336.357468 -233.660442)
		(width 0.088646)
		(layer "In4.Cu")
		(net "M_B_CPU0_SB_DQ<6>")
	)
	(arc
		(start 337.307682 -233.666792)
		(mid 337.029359 -233.591033)
		(end 336.749898 -233.662474)
		(width 0.088646)
		(layer "In4.Cu")
		(net "M_B_CPU0_SB_DQ<6>")
	)
	(arc
		(start 337.67776 -233.669332)
		(mid 337.492375 -233.71697)
		(end 337.307682 -233.666792)
		(width 0.088646)
		(layer "In4.Cu")
		(net "M_B_CPU0_SB_DQ<6>")
	)
	(arc
		(start 334.488536 -233.666538)
		(mid 334.205834 -233.590796)
		(end 333.923132 -233.666538)
		(width 0.088646)
		(layer "In4.Cu")
		(net "M_B_CPU0_SB_DQ<6>")
	)
	(arc
		(start 332.608936 -233.666538)
		(mid 332.252413 -233.595635)
		(end 331.926438 -233.756454)
		(width 0.088646)
		(layer "In4.Cu")
		(net "M_B_CPU0_SB_DQ<6>")
	)
	(arc
		(start 340.485222 -233.675936)
		(mid 340.304986 -233.716928)
		(end 340.127082 -233.666792)
		(width 0.088646)
		(layer "In4.Cu")
		(net "M_B_CPU0_SB_DQ<6>")
	)
	(arc
		(start 336.357468 -233.660442)
		(mid 336.07929 -233.59075)
		(end 335.802732 -233.666538)
		(width 0.088646)
		(layer "In4.Cu")
		(net "M_B_CPU0_SB_DQ<6>")
	)
	(arc
		(start 333.548736 -233.666538)
		(mid 333.266034 -233.590796)
		(end 332.983332 -233.666538)
		(width 0.088646)
		(layer "In4.Cu")
		(net "M_B_CPU0_SB_DQ<6>")
	)
	(arc
		(start 336.738722 -233.668824)
		(mid 336.553032 -233.716902)
		(end 336.367882 -233.666792)
		(width 0.088646)
		(layer "In4.Cu")
		(net "M_B_CPU0_SB_DQ<6>")
	)
	(arc
		(start 335.802732 -233.666538)
		(mid 335.615534 -233.716681)
		(end 335.428336 -233.666538)
		(width 0.088646)
		(layer "In4.Cu")
		(net "M_B_CPU0_SB_DQ<6>")
	)
	(arc
		(start 335.428336 -233.666538)
		(mid 335.145634 -233.590796)
		(end 334.862932 -233.666538)
		(width 0.088646)
		(layer "In4.Cu")
		(net "M_B_CPU0_SB_DQ<6>")
	)
	(arc
		(start 338.61756 -233.669332)
		(mid 338.432175 -233.71697)
		(end 338.247482 -233.666792)
		(width 0.088646)
		(layer "In4.Cu")
		(net "M_B_CPU0_SB_DQ<6>")
	)
	(arc
		(start 332.983332 -233.666538)
		(mid 332.796134 -233.716681)
		(end 332.608936 -233.666538)
		(width 0.088646)
		(layer "In4.Cu")
		(net "M_B_CPU0_SB_DQ<6>")
	)
	(arc
		(start 338.247482 -233.666792)
		(mid 337.969159 -233.591033)
		(end 337.689698 -233.662474)
		(width 0.088646)
		(layer "In4.Cu")
		(net "M_B_CPU0_SB_DQ<6>")
	)
	(arc
		(start 333.923132 -233.666538)
		(mid 333.735934 -233.716681)
		(end 333.548736 -233.666538)
		(width 0.088646)
		(layer "In4.Cu")
		(net "M_B_CPU0_SB_DQ<6>")
	)
	(arc
		(start 340.127082 -233.666792)
		(mid 339.848759 -233.591033)
		(end 339.569298 -233.662474)
		(width 0.088646)
		(layer "In4.Cu")
		(net "M_B_CPU0_SB_DQ<6>")
	)
	(arc
		(start 334.862932 -233.666538)
		(mid 334.675734 -233.716681)
		(end 334.488536 -233.666538)
		(width 0.088646)
		(layer "In4.Cu")
		(net "M_B_CPU0_SB_DQ<6>")
	)
	(arc
		(start 339.187282 -233.666792)
		(mid 338.908959 -233.591033)
		(end 338.629498 -233.662474)
		(width 0.088646)
		(layer "In4.Cu")
		(net "M_B_CPU0_SB_DQ<6>")
	)
	(arc
		(start 339.55736 -233.669332)
		(mid 339.371975 -233.71697)
		(end 339.187282 -233.666792)
		(width 0.088646)
		(layer "In4.Cu")
		(net "M_B_CPU0_SB_DQ<6>")
	)
	(arc
		(start 341.18042 -233.738928)
		(mid 340.841933 -233.606688)
		(end 340.485222 -233.675936)
		(width 0.088646)
		(layer "In4.Cu")
		(net "M_B_CPU0_SB_DQ<6>")
	)
	(segment
		(start 340.31428 -233.877866)
		(end 340.31428 -233.34218)
		(width 0.20066)
		(layer "F.Cu")
		(net "M_B_CPU0_SB_DQ<5>")
	)
	(segment
		(start 291.225986 -224.091754)
		(end 289.240468 -224.091754)
		(width 0.1016)
		(layer "F.Cu")
		(net "M_B_CPU0_SB_DQ<5>")
	)
	(segment
		(start 294.904414 -224.516696)
		(end 293.799514 -224.516696)
		(width 0.20066)
		(layer "F.Cu")
		(net "M_B_CPU0_SB_DQ<5>")
	)
	(segment
		(start 293.799514 -224.516696)
		(end 292.160198 -224.516696)
		(width 0.20066)
		(layer "F.Cu")
		(net "M_B_CPU0_SB_DQ<5>")
	)
	(segment
		(start 289.240468 -224.091754)
		(end 289.231578 -224.082864)
		(width 0.1016)
		(layer "F.Cu")
		(net "M_B_CPU0_SB_DQ<5>")
	)
	(segment
		(start 288.46018 -224.245424)
		(end 288.46018 -224.573592)
		(width 0.20066)
		(layer "F.Cu")
		(net "M_B_CPU0_SB_DQ<5>")
	)
	(segment
		(start 340.314534 -233.87812)
		(end 340.31428 -233.877866)
		(width 0.20066)
		(layer "F.Cu")
		(net "M_B_CPU0_SB_DQ<5>")
	)
	(segment
		(start 288.62274 -224.082864)
		(end 288.46018 -224.245424)
		(width 0.20066)
		(layer "F.Cu")
		(net "M_B_CPU0_SB_DQ<5>")
	)
	(segment
		(start 287.589976 -224.516696)
		(end 286.255714 -224.516696)
		(width 0.20066)
		(layer "F.Cu")
		(net "M_B_CPU0_SB_DQ<5>")
	)
	(segment
		(start 287.801304 -224.728024)
		(end 287.589976 -224.516696)
		(width 0.20066)
		(layer "F.Cu")
		(net "M_B_CPU0_SB_DQ<5>")
	)
	(segment
		(start 291.556694 -224.091754)
		(end 291.225986 -224.091754)
		(width 0.101854)
		(layer "F.Cu")
		(net "M_B_CPU0_SB_DQ<5>")
	)
	(segment
		(start 291.735256 -224.091754)
		(end 291.556694 -224.091754)
		(width 0.20066)
		(layer "F.Cu")
		(net "M_B_CPU0_SB_DQ<5>")
	)
	(segment
		(start 289.231578 -224.082864)
		(end 288.62274 -224.082864)
		(width 0.20066)
		(layer "F.Cu")
		(net "M_B_CPU0_SB_DQ<5>")
	)
	(segment
		(start 288.305748 -224.728024)
		(end 287.801304 -224.728024)
		(width 0.20066)
		(layer "F.Cu")
		(net "M_B_CPU0_SB_DQ<5>")
	)
	(segment
		(start 288.46018 -224.573592)
		(end 288.305748 -224.728024)
		(width 0.20066)
		(layer "F.Cu")
		(net "M_B_CPU0_SB_DQ<5>")
	)
	(segment
		(start 292.160198 -224.516696)
		(end 291.735256 -224.091754)
		(width 0.20066)
		(layer "F.Cu")
		(net "M_B_CPU0_SB_DQ<5>")
	)
	(segment
		(start 331.04455 -232.92943)
		(end 330.648564 -232.92943)
		(width 0.088646)
		(layer "In4.Cu")
		(net "M_B_CPU0_SB_DQ<5>")
	)
	(segment
		(start 295.329356 -224.091754)
		(end 294.904414 -224.516696)
		(width 0.18288)
		(layer "In4.Cu")
		(net "M_B_CPU0_SB_DQ<5>")
	)
	(segment
		(start 315.623448 -224.67316)
		(end 314.669932 -222.371158)
		(width 0.18288)
		(layer "In4.Cu")
		(net "M_B_CPU0_SB_DQ<5>")
	)
	(segment
		(start 331.203046 -233.087926)
		(end 331.04455 -232.92943)
		(width 0.088646)
		(layer "In4.Cu")
		(net "M_B_CPU0_SB_DQ<5>")
	)
	(segment
		(start 331.701648 -232.967276)
		(end 331.580998 -233.087926)
		(width 0.088646)
		(layer "In4.Cu")
		(net "M_B_CPU0_SB_DQ<5>")
	)
	(segment
		(start 313.884056 -221.585282)
		(end 310.581294 -221.585282)
		(width 0.18288)
		(layer "In4.Cu")
		(net "M_B_CPU0_SB_DQ<5>")
	)
	(segment
		(start 306.446174 -222.200216)
		(end 305.835558 -222.200216)
		(width 0.18288)
		(layer "In4.Cu")
		(net "M_B_CPU0_SB_DQ<5>")
	)
	(segment
		(start 302.976534 -224.091754)
		(end 295.329356 -224.091754)
		(width 0.18288)
		(layer "In4.Cu")
		(net "M_B_CPU0_SB_DQ<5>")
	)
	(segment
		(start 310.311292 -221.31528)
		(end 307.33111 -221.31528)
		(width 0.18288)
		(layer "In4.Cu")
		(net "M_B_CPU0_SB_DQ<5>")
	)
	(segment
		(start 336.742532 -233.017822)
		(end 336.738722 -233.015536)
		(width 0.088646)
		(layer "In4.Cu")
		(net "M_B_CPU0_SB_DQ<5>")
	)
	(segment
		(start 303.748186 -223.320102)
		(end 302.976534 -224.091754)
		(width 0.18288)
		(layer "In4.Cu")
		(net "M_B_CPU0_SB_DQ<5>")
	)
	(segment
		(start 307.33111 -221.31528)
		(end 306.446174 -222.200216)
		(width 0.18288)
		(layer "In4.Cu")
		(net "M_B_CPU0_SB_DQ<5>")
	)
	(segment
		(start 310.581294 -221.585282)
		(end 310.311292 -221.31528)
		(width 0.18288)
		(layer "In4.Cu")
		(net "M_B_CPU0_SB_DQ<5>")
	)
	(segment
		(start 336.748374 -233.021124)
		(end 336.742532 -233.017822)
		(width 0.088646)
		(layer "In4.Cu")
		(net "M_B_CPU0_SB_DQ<5>")
	)
	(segment
		(start 338.627974 -233.021124)
		(end 338.61629 -233.01452)
		(width 0.088646)
		(layer "In4.Cu")
		(net "M_B_CPU0_SB_DQ<5>")
	)
	(segment
		(start 323.879718 -232.92943)
		(end 315.623448 -224.67316)
		(width 0.18288)
		(layer "In4.Cu")
		(net "M_B_CPU0_SB_DQ<5>")
	)
	(segment
		(start 314.669932 -222.371158)
		(end 313.884056 -221.585282)
		(width 0.18288)
		(layer "In4.Cu")
		(net "M_B_CPU0_SB_DQ<5>")
	)
	(segment
		(start 304.715672 -223.320102)
		(end 303.748186 -223.320102)
		(width 0.18288)
		(layer "In4.Cu")
		(net "M_B_CPU0_SB_DQ<5>")
	)
	(segment
		(start 331.856334 -232.967276)
		(end 331.701648 -232.967276)
		(width 0.088646)
		(layer "In4.Cu")
		(net "M_B_CPU0_SB_DQ<5>")
	)
	(segment
		(start 337.688174 -233.021124)
		(end 337.67649 -233.01452)
		(width 0.088646)
		(layer "In4.Cu")
		(net "M_B_CPU0_SB_DQ<5>")
	)
	(segment
		(start 305.835558 -222.200216)
		(end 304.715672 -223.320102)
		(width 0.18288)
		(layer "In4.Cu")
		(net "M_B_CPU0_SB_DQ<5>")
	)
	(segment
		(start 330.648564 -232.92943)
		(end 323.879718 -232.92943)
		(width 0.18288)
		(layer "In4.Cu")
		(net "M_B_CPU0_SB_DQ<5>")
	)
	(segment
		(start 339.567774 -233.021124)
		(end 339.55609 -233.01452)
		(width 0.088646)
		(layer "In4.Cu")
		(net "M_B_CPU0_SB_DQ<5>")
	)
	(segment
		(start 331.580998 -233.087926)
		(end 331.203046 -233.087926)
		(width 0.088646)
		(layer "In4.Cu")
		(net "M_B_CPU0_SB_DQ<5>")
	)
	(segment
		(start 332.998064 -233.026458)
		(end 332.983332 -233.017822)
		(width 0.088646)
		(layer "In4.Cu")
		(net "M_B_CPU0_SB_DQ<5>")
	)
	(segment
		(start 332.058264 -233.026458)
		(end 332.043532 -233.017822)
		(width 0.088646)
		(layer "In4.Cu")
		(net "M_B_CPU0_SB_DQ<5>")
	)
	(arc
		(start 334.862932 -233.017822)
		(mid 334.675734 -232.967679)
		(end 334.488536 -233.017822)
		(width 0.088646)
		(layer "In4.Cu")
		(net "M_B_CPU0_SB_DQ<5>")
	)
	(arc
		(start 334.488536 -233.017822)
		(mid 334.205834 -233.093598)
		(end 333.923132 -233.017822)
		(width 0.088646)
		(layer "In4.Cu")
		(net "M_B_CPU0_SB_DQ<5>")
	)
	(arc
		(start 339.55609 -233.01452)
		(mid 339.371235 -232.96757)
		(end 339.187282 -233.017822)
		(width 0.088646)
		(layer "In4.Cu")
		(net "M_B_CPU0_SB_DQ<5>")
	)
	(arc
		(start 333.548736 -233.017822)
		(mid 333.274537 -233.093657)
		(end 332.998064 -233.026458)
		(width 0.088646)
		(layer "In4.Cu")
		(net "M_B_CPU0_SB_DQ<5>")
	)
	(arc
		(start 337.67649 -233.01452)
		(mid 337.491635 -232.96757)
		(end 337.307682 -233.017822)
		(width 0.088646)
		(layer "In4.Cu")
		(net "M_B_CPU0_SB_DQ<5>")
	)
	(arc
		(start 332.983332 -233.017822)
		(mid 332.796134 -232.967679)
		(end 332.608936 -233.017822)
		(width 0.088646)
		(layer "In4.Cu")
		(net "M_B_CPU0_SB_DQ<5>")
	)
	(arc
		(start 332.608936 -233.017822)
		(mid 332.334737 -233.093657)
		(end 332.058264 -233.026458)
		(width 0.088646)
		(layer "In4.Cu")
		(net "M_B_CPU0_SB_DQ<5>")
	)
	(arc
		(start 335.802732 -233.017822)
		(mid 335.615534 -232.967679)
		(end 335.428336 -233.017822)
		(width 0.088646)
		(layer "In4.Cu")
		(net "M_B_CPU0_SB_DQ<5>")
	)
	(arc
		(start 336.738722 -233.015536)
		(mid 336.553003 -232.967584)
		(end 336.367882 -233.017822)
		(width 0.088646)
		(layer "In4.Cu")
		(net "M_B_CPU0_SB_DQ<5>")
	)
	(arc
		(start 340.127082 -233.017822)
		(mid 339.847879 -233.093462)
		(end 339.567774 -233.021124)
		(width 0.088646)
		(layer "In4.Cu")
		(net "M_B_CPU0_SB_DQ<5>")
	)
	(arc
		(start 336.367882 -233.017822)
		(mid 336.085324 -233.093471)
		(end 335.802732 -233.017822)
		(width 0.088646)
		(layer "In4.Cu")
		(net "M_B_CPU0_SB_DQ<5>")
	)
	(arc
		(start 338.247482 -233.017822)
		(mid 337.968279 -233.093462)
		(end 337.688174 -233.021124)
		(width 0.088646)
		(layer "In4.Cu")
		(net "M_B_CPU0_SB_DQ<5>")
	)
	(arc
		(start 339.187282 -233.017822)
		(mid 338.908079 -233.093462)
		(end 338.627974 -233.021124)
		(width 0.088646)
		(layer "In4.Cu")
		(net "M_B_CPU0_SB_DQ<5>")
	)
	(arc
		(start 340.31428 -233.34218)
		(mid 340.382693 -233.086552)
		(end 340.127082 -233.017822)
		(width 0.088646)
		(layer "In4.Cu")
		(net "M_B_CPU0_SB_DQ<5>")
	)
	(arc
		(start 333.923132 -233.017822)
		(mid 333.735934 -232.967679)
		(end 333.548736 -233.017822)
		(width 0.088646)
		(layer "In4.Cu")
		(net "M_B_CPU0_SB_DQ<5>")
	)
	(arc
		(start 337.307682 -233.017822)
		(mid 337.028479 -233.093462)
		(end 336.748374 -233.021124)
		(width 0.088646)
		(layer "In4.Cu")
		(net "M_B_CPU0_SB_DQ<5>")
	)
	(arc
		(start 335.428336 -233.017822)
		(mid 335.145634 -233.093598)
		(end 334.862932 -233.017822)
		(width 0.088646)
		(layer "In4.Cu")
		(net "M_B_CPU0_SB_DQ<5>")
	)
	(arc
		(start 338.61629 -233.01452)
		(mid 338.431435 -232.96757)
		(end 338.247482 -233.017822)
		(width 0.088646)
		(layer "In4.Cu")
		(net "M_B_CPU0_SB_DQ<5>")
	)
	(arc
		(start 332.043532 -233.017822)
		(mid 331.95326 -232.980223)
		(end 331.856334 -232.967276)
		(width 0.088646)
		(layer "In4.Cu")
		(net "M_B_CPU0_SB_DQ<5>")
	)
	(segment
		(start 287.589976 -226.216718)
		(end 286.255714 -226.216718)
		(width 0.20066)
		(layer "F.Cu")
		(net "M_B_CPU0_SB_DQ<4>")
	)
	(segment
		(start 294.904414 -226.216718)
		(end 293.799514 -226.216718)
		(width 0.20066)
		(layer "F.Cu")
		(net "M_B_CPU0_SB_DQ<4>")
	)
	(segment
		(start 287.828736 -226.455478)
		(end 287.589976 -226.216718)
		(width 0.20066)
		(layer "F.Cu")
		(net "M_B_CPU0_SB_DQ<4>")
	)
	(segment
		(start 339.84438 -234.69219)
		(end 339.844634 -234.691936)
		(width 0.20066)
		(layer "F.Cu")
		(net "M_B_CPU0_SB_DQ<4>")
	)
	(segment
		(start 288.46018 -226.282758)
		(end 288.28746 -226.455478)
		(width 0.20066)
		(layer "F.Cu")
		(net "M_B_CPU0_SB_DQ<4>")
	)
	(segment
		(start 292.430454 -226.216718)
		(end 292.005512 -225.791776)
		(width 0.20066)
		(layer "F.Cu")
		(net "M_B_CPU0_SB_DQ<4>")
	)
	(segment
		(start 289.48761 -225.791776)
		(end 289.239706 -225.791776)
		(width 0.101854)
		(layer "F.Cu")
		(net "M_B_CPU0_SB_DQ<4>")
	)
	(segment
		(start 289.231578 -225.783648)
		(end 288.66973 -225.783648)
		(width 0.20066)
		(layer "F.Cu")
		(net "M_B_CPU0_SB_DQ<4>")
	)
	(segment
		(start 293.799514 -226.216718)
		(end 292.430454 -226.216718)
		(width 0.20066)
		(layer "F.Cu")
		(net "M_B_CPU0_SB_DQ<4>")
	)
	(segment
		(start 339.844634 -234.691936)
		(end 339.844634 -234.15625)
		(width 0.20066)
		(layer "F.Cu")
		(net "M_B_CPU0_SB_DQ<4>")
	)
	(segment
		(start 291.556694 -225.791776)
		(end 289.48761 -225.791776)
		(width 0.1016)
		(layer "F.Cu")
		(net "M_B_CPU0_SB_DQ<4>")
	)
	(segment
		(start 288.28746 -226.455478)
		(end 287.828736 -226.455478)
		(width 0.20066)
		(layer "F.Cu")
		(net "M_B_CPU0_SB_DQ<4>")
	)
	(segment
		(start 292.005512 -225.791776)
		(end 291.556694 -225.791776)
		(width 0.20066)
		(layer "F.Cu")
		(net "M_B_CPU0_SB_DQ<4>")
	)
	(segment
		(start 288.46018 -225.993198)
		(end 288.46018 -226.282758)
		(width 0.20066)
		(layer "F.Cu")
		(net "M_B_CPU0_SB_DQ<4>")
	)
	(segment
		(start 288.66973 -225.783648)
		(end 288.46018 -225.993198)
		(width 0.20066)
		(layer "F.Cu")
		(net "M_B_CPU0_SB_DQ<4>")
	)
	(segment
		(start 289.239706 -225.791776)
		(end 289.231578 -225.783648)
		(width 0.101854)
		(layer "F.Cu")
		(net "M_B_CPU0_SB_DQ<4>")
	)
	(segment
		(start 331.304138 -233.92511)
		(end 330.648564 -233.92511)
		(width 0.088646)
		(layer "In4.Cu")
		(net "M_B_CPU0_SB_DQ<4>")
	)
	(segment
		(start 295.329356 -225.791776)
		(end 294.904414 -226.216718)
		(width 0.18288)
		(layer "In4.Cu")
		(net "M_B_CPU0_SB_DQ<4>")
	)
	(segment
		(start 339.844634 -234.15625)
		(end 339.3948 -233.997246)
		(width 0.088646)
		(layer "In4.Cu")
		(net "M_B_CPU0_SB_DQ<4>")
	)
	(segment
		(start 338.721954 -233.829098)
		(end 338.717382 -233.831638)
		(width 0.088646)
		(layer "In4.Cu")
		(net "M_B_CPU0_SB_DQ<4>")
	)
	(segment
		(start 312.93054 -224.042224)
		(end 312.666126 -223.77781)
		(width 0.18288)
		(layer "In4.Cu")
		(net "M_B_CPU0_SB_DQ<4>")
	)
	(segment
		(start 314.363862 -224.94367)
		(end 313.266582 -224.94367)
		(width 0.18288)
		(layer "In4.Cu")
		(net "M_B_CPU0_SB_DQ<4>")
	)
	(segment
		(start 336.837782 -233.831638)
		(end 336.83321 -233.834432)
		(width 0.088646)
		(layer "In4.Cu")
		(net "M_B_CPU0_SB_DQ<4>")
	)
	(segment
		(start 311.975754 -223.96704)
		(end 311.138062 -223.129348)
		(width 0.18288)
		(layer "In4.Cu")
		(net "M_B_CPU0_SB_DQ<4>")
	)
	(segment
		(start 297.001438 -225.252788)
		(end 296.818558 -225.069908)
		(width 0.18288)
		(layer "In4.Cu")
		(net "M_B_CPU0_SB_DQ<4>")
	)
	(segment
		(start 336.272632 -233.831638)
		(end 336.272632 -233.831892)
		(width 0.088646)
		(layer "In4.Cu")
		(net "M_B_CPU0_SB_DQ<4>")
	)
	(segment
		(start 297.001438 -225.608896)
		(end 297.001438 -225.252788)
		(width 0.18288)
		(layer "In4.Cu")
		(net "M_B_CPU0_SB_DQ<4>")
	)
	(segment
		(start 307.601366 -223.129348)
		(end 306.826158 -223.904556)
		(width 0.18288)
		(layer "In4.Cu")
		(net "M_B_CPU0_SB_DQ<4>")
	)
	(segment
		(start 313.266582 -224.94367)
		(end 312.873898 -224.550986)
		(width 0.18288)
		(layer "In4.Cu")
		(net "M_B_CPU0_SB_DQ<4>")
	)
	(segment
		(start 312.666126 -223.77781)
		(end 312.440066 -223.77781)
		(width 0.18288)
		(layer "In4.Cu")
		(net "M_B_CPU0_SB_DQ<4>")
	)
	(segment
		(start 331.414882 -234.035854)
		(end 331.304138 -233.92511)
		(width 0.088646)
		(layer "In4.Cu")
		(net "M_B_CPU0_SB_DQ<4>")
	)
	(segment
		(start 339.314282 -233.960162)
		(end 339.092032 -233.831638)
		(width 0.088646)
		(layer "In4.Cu")
		(net "M_B_CPU0_SB_DQ<4>")
	)
	(segment
		(start 296.310558 -225.608896)
		(end 296.127678 -225.791776)
		(width 0.18288)
		(layer "In4.Cu")
		(net "M_B_CPU0_SB_DQ<4>")
	)
	(segment
		(start 331.916278 -234.035854)
		(end 331.414882 -234.035854)
		(width 0.088646)
		(layer "In4.Cu")
		(net "M_B_CPU0_SB_DQ<4>")
	)
	(segment
		(start 338.717382 -233.831638)
		(end 338.710016 -233.835956)
		(width 0.088646)
		(layer "In4.Cu")
		(net "M_B_CPU0_SB_DQ<4>")
	)
	(segment
		(start 330.648564 -233.92511)
		(end 323.345302 -233.92511)
		(width 0.18288)
		(layer "In4.Cu")
		(net "M_B_CPU0_SB_DQ<4>")
	)
	(segment
		(start 296.818558 -225.069908)
		(end 296.493438 -225.069908)
		(width 0.18288)
		(layer "In4.Cu")
		(net "M_B_CPU0_SB_DQ<4>")
	)
	(segment
		(start 312.250836 -223.96704)
		(end 311.975754 -223.96704)
		(width 0.18288)
		(layer "In4.Cu")
		(net "M_B_CPU0_SB_DQ<4>")
	)
	(segment
		(start 299.524166 -225.810826)
		(end 299.505116 -225.791776)
		(width 0.18288)
		(layer "In4.Cu")
		(net "M_B_CPU0_SB_DQ<4>")
	)
	(segment
		(start 312.873898 -224.550986)
		(end 312.873898 -224.324926)
		(width 0.18288)
		(layer "In4.Cu")
		(net "M_B_CPU0_SB_DQ<4>")
	)
	(segment
		(start 296.493438 -225.069908)
		(end 296.310558 -225.252788)
		(width 0.18288)
		(layer "In4.Cu")
		(net "M_B_CPU0_SB_DQ<4>")
	)
	(segment
		(start 312.873898 -224.324926)
		(end 312.93054 -224.268284)
		(width 0.18288)
		(layer "In4.Cu")
		(net "M_B_CPU0_SB_DQ<4>")
	)
	(segment
		(start 312.440066 -223.77781)
		(end 312.250836 -223.96704)
		(width 0.18288)
		(layer "In4.Cu")
		(net "M_B_CPU0_SB_DQ<4>")
	)
	(segment
		(start 311.138062 -223.129348)
		(end 307.601366 -223.129348)
		(width 0.18288)
		(layer "In4.Cu")
		(net "M_B_CPU0_SB_DQ<4>")
	)
	(segment
		(start 336.842354 -233.829098)
		(end 336.837782 -233.831638)
		(width 0.088646)
		(layer "In4.Cu")
		(net "M_B_CPU0_SB_DQ<4>")
	)
	(segment
		(start 306.826158 -223.904556)
		(end 306.074064 -223.904556)
		(width 0.18288)
		(layer "In4.Cu")
		(net "M_B_CPU0_SB_DQ<4>")
	)
	(segment
		(start 306.074064 -223.904556)
		(end 304.167794 -225.810826)
		(width 0.18288)
		(layer "In4.Cu")
		(net "M_B_CPU0_SB_DQ<4>")
	)
	(segment
		(start 332.061058 -233.891074)
		(end 331.916278 -234.035854)
		(width 0.088646)
		(layer "In4.Cu")
		(net "M_B_CPU0_SB_DQ<4>")
	)
	(segment
		(start 304.167794 -225.810826)
		(end 299.524166 -225.810826)
		(width 0.18288)
		(layer "In4.Cu")
		(net "M_B_CPU0_SB_DQ<4>")
	)
	(segment
		(start 297.184318 -225.791776)
		(end 297.001438 -225.608896)
		(width 0.18288)
		(layer "In4.Cu")
		(net "M_B_CPU0_SB_DQ<4>")
	)
	(segment
		(start 337.782154 -233.829098)
		(end 337.770216 -233.835956)
		(width 0.088646)
		(layer "In4.Cu")
		(net "M_B_CPU0_SB_DQ<4>")
	)
	(segment
		(start 323.345302 -233.92511)
		(end 314.363862 -224.94367)
		(width 0.18288)
		(layer "In4.Cu")
		(net "M_B_CPU0_SB_DQ<4>")
	)
	(segment
		(start 296.127678 -225.791776)
		(end 295.329356 -225.791776)
		(width 0.18288)
		(layer "In4.Cu")
		(net "M_B_CPU0_SB_DQ<4>")
	)
	(segment
		(start 312.93054 -224.268284)
		(end 312.93054 -224.042224)
		(width 0.18288)
		(layer "In4.Cu")
		(net "M_B_CPU0_SB_DQ<4>")
	)
	(segment
		(start 299.505116 -225.791776)
		(end 297.184318 -225.791776)
		(width 0.18288)
		(layer "In4.Cu")
		(net "M_B_CPU0_SB_DQ<4>")
	)
	(segment
		(start 296.310558 -225.252788)
		(end 296.310558 -225.608896)
		(width 0.18288)
		(layer "In4.Cu")
		(net "M_B_CPU0_SB_DQ<4>")
	)
	(arc
		(start 335.332832 -233.831892)
		(mid 335.145634 -233.781749)
		(end 334.958436 -233.831892)
		(width 0.088646)
		(layer "In4.Cu")
		(net "M_B_CPU0_SB_DQ<4>")
	)
	(arc
		(start 336.272632 -233.831892)
		(mid 336.085434 -233.781749)
		(end 335.898236 -233.831892)
		(width 0.088646)
		(layer "In4.Cu")
		(net "M_B_CPU0_SB_DQ<4>")
	)
	(arc
		(start 338.152232 -233.831638)
		(mid 337.967538 -233.781537)
		(end 337.782154 -233.829098)
		(width 0.088646)
		(layer "In4.Cu")
		(net "M_B_CPU0_SB_DQ<4>")
	)
	(arc
		(start 332.513432 -233.831892)
		(mid 332.326234 -233.781749)
		(end 332.139036 -233.831892)
		(width 0.088646)
		(layer "In4.Cu")
		(net "M_B_CPU0_SB_DQ<4>")
	)
	(arc
		(start 335.898236 -233.831892)
		(mid 335.615534 -233.907634)
		(end 335.332832 -233.831892)
		(width 0.088646)
		(layer "In4.Cu")
		(net "M_B_CPU0_SB_DQ<4>")
	)
	(arc
		(start 339.092032 -233.831638)
		(mid 338.907338 -233.781537)
		(end 338.721954 -233.829098)
		(width 0.088646)
		(layer "In4.Cu")
		(net "M_B_CPU0_SB_DQ<4>")
	)
	(arc
		(start 337.212432 -233.831638)
		(mid 337.027738 -233.781537)
		(end 336.842354 -233.829098)
		(width 0.088646)
		(layer "In4.Cu")
		(net "M_B_CPU0_SB_DQ<4>")
	)
	(arc
		(start 334.958436 -233.831892)
		(mid 334.675734 -233.907634)
		(end 334.393032 -233.831892)
		(width 0.088646)
		(layer "In4.Cu")
		(net "M_B_CPU0_SB_DQ<4>")
	)
	(arc
		(start 334.393032 -233.831892)
		(mid 334.205834 -233.781749)
		(end 334.018636 -233.831892)
		(width 0.088646)
		(layer "In4.Cu")
		(net "M_B_CPU0_SB_DQ<4>")
	)
	(arc
		(start 337.770216 -233.835956)
		(mid 337.490755 -233.907393)
		(end 337.212432 -233.831638)
		(width 0.088646)
		(layer "In4.Cu")
		(net "M_B_CPU0_SB_DQ<4>")
	)
	(arc
		(start 332.139036 -233.831892)
		(mid 332.098106 -233.858925)
		(end 332.061058 -233.891074)
		(width 0.088646)
		(layer "In4.Cu")
		(net "M_B_CPU0_SB_DQ<4>")
	)
	(arc
		(start 333.453232 -233.831892)
		(mid 333.266034 -233.781749)
		(end 333.078836 -233.831892)
		(width 0.088646)
		(layer "In4.Cu")
		(net "M_B_CPU0_SB_DQ<4>")
	)
	(arc
		(start 333.078836 -233.831892)
		(mid 332.796134 -233.907634)
		(end 332.513432 -233.831892)
		(width 0.088646)
		(layer "In4.Cu")
		(net "M_B_CPU0_SB_DQ<4>")
	)
	(arc
		(start 338.710016 -233.835956)
		(mid 338.430555 -233.907393)
		(end 338.152232 -233.831638)
		(width 0.088646)
		(layer "In4.Cu")
		(net "M_B_CPU0_SB_DQ<4>")
	)
	(arc
		(start 334.018636 -233.831892)
		(mid 333.735934 -233.907634)
		(end 333.453232 -233.831892)
		(width 0.088646)
		(layer "In4.Cu")
		(net "M_B_CPU0_SB_DQ<4>")
	)
	(arc
		(start 339.3948 -233.997246)
		(mid 339.35369 -233.980552)
		(end 339.314282 -233.960162)
		(width 0.088646)
		(layer "In4.Cu")
		(net "M_B_CPU0_SB_DQ<4>")
	)
	(arc
		(start 336.83321 -233.834432)
		(mid 336.552546 -233.90744)
		(end 336.272632 -233.831638)
		(width 0.088646)
		(layer "In4.Cu")
		(net "M_B_CPU0_SB_DQ<4>")
	)
	(segment
		(start 292.67531 -230.055928)
		(end 292.321488 -230.055928)
		(width 0.20066)
		(layer "F.Cu")
		(net "M_B_CPU0_SB_DQ<3>")
	)
	(segment
		(start 296.217594 -229.612444)
		(end 295.82237 -229.612444)
		(width 0.20066)
		(layer "F.Cu")
		(net "M_B_CPU0_SB_DQ<3>")
	)
	(segment
		(start 292.689534 -230.041704)
		(end 292.67531 -230.055928)
		(width 0.101854)
		(layer "F.Cu")
		(net "M_B_CPU0_SB_DQ<3>")
	)
	(segment
		(start 292.05301 -229.616762)
		(end 290.355782 -229.616762)
		(width 0.20066)
		(layer "F.Cu")
		(net "M_B_CPU0_SB_DQ<3>")
	)
	(segment
		(start 341.724234 -236.319568)
		(end 341.724234 -235.783882)
		(width 0.20066)
		(layer "F.Cu")
		(net "M_B_CPU0_SB_DQ<3>")
	)
	(segment
		(start 296.875962 -229.82428)
		(end 296.42943 -229.82428)
		(width 0.20066)
		(layer "F.Cu")
		(net "M_B_CPU0_SB_DQ<3>")
	)
	(segment
		(start 292.927532 -230.041704)
		(end 292.689534 -230.041704)
		(width 0.101854)
		(layer "F.Cu")
		(net "M_B_CPU0_SB_DQ<3>")
	)
	(segment
		(start 296.42943 -229.82428)
		(end 296.217594 -229.612444)
		(width 0.20066)
		(layer "F.Cu")
		(net "M_B_CPU0_SB_DQ<3>")
	)
	(segment
		(start 295.693846 -229.892606)
		(end 295.544748 -230.041704)
		(width 0.20066)
		(layer "F.Cu")
		(net "M_B_CPU0_SB_DQ<3>")
	)
	(segment
		(start 292.178994 -229.742746)
		(end 292.05301 -229.616762)
		(width 0.20066)
		(layer "F.Cu")
		(net "M_B_CPU0_SB_DQ<3>")
	)
	(segment
		(start 292.321488 -230.055928)
		(end 292.178994 -229.913434)
		(width 0.20066)
		(layer "F.Cu")
		(net "M_B_CPU0_SB_DQ<3>")
	)
	(segment
		(start 341.72398 -236.319822)
		(end 341.724234 -236.319568)
		(width 0.20066)
		(layer "F.Cu")
		(net "M_B_CPU0_SB_DQ<3>")
	)
	(segment
		(start 297.08348 -229.616762)
		(end 296.875962 -229.82428)
		(width 0.20066)
		(layer "F.Cu")
		(net "M_B_CPU0_SB_DQ<3>")
	)
	(segment
		(start 295.544748 -230.041704)
		(end 295.000426 -230.041704)
		(width 0.20066)
		(layer "F.Cu")
		(net "M_B_CPU0_SB_DQ<3>")
	)
	(segment
		(start 299.004482 -229.616762)
		(end 297.899582 -229.616762)
		(width 0.20066)
		(layer "F.Cu")
		(net "M_B_CPU0_SB_DQ<3>")
	)
	(segment
		(start 292.178994 -229.913434)
		(end 292.178994 -229.742746)
		(width 0.20066)
		(layer "F.Cu")
		(net "M_B_CPU0_SB_DQ<3>")
	)
	(segment
		(start 295.82237 -229.612444)
		(end 295.693846 -229.740968)
		(width 0.20066)
		(layer "F.Cu")
		(net "M_B_CPU0_SB_DQ<3>")
	)
	(segment
		(start 297.899582 -229.616762)
		(end 297.08348 -229.616762)
		(width 0.20066)
		(layer "F.Cu")
		(net "M_B_CPU0_SB_DQ<3>")
	)
	(segment
		(start 295.693846 -229.740968)
		(end 295.693846 -229.892606)
		(width 0.20066)
		(layer "F.Cu")
		(net "M_B_CPU0_SB_DQ<3>")
	)
	(segment
		(start 295.000426 -230.041704)
		(end 292.927532 -230.041704)
		(width 0.1016)
		(layer "F.Cu")
		(net "M_B_CPU0_SB_DQ<3>")
	)
	(segment
		(start 341.36838 -235.688632)
		(end 340.971632 -235.459524)
		(width 0.088646)
		(layer "In4.Cu")
		(net "M_B_CPU0_SB_DQ<3>")
	)
	(segment
		(start 306.33797 -228.09073)
		(end 306.33797 -228.349302)
		(width 0.18288)
		(layer "In4.Cu")
		(net "M_B_CPU0_SB_DQ<3>")
	)
	(segment
		(start 338.717382 -236.108494)
		(end 338.710016 -236.104176)
		(width 0.088646)
		(layer "In4.Cu")
		(net "M_B_CPU0_SB_DQ<3>")
	)
	(segment
		(start 311.242202 -229.00894)
		(end 311.242202 -228.07041)
		(width 0.18288)
		(layer "In4.Cu")
		(net "M_B_CPU0_SB_DQ<3>")
	)
	(segment
		(start 310.551322 -229.00894)
		(end 310.368442 -229.19182)
		(width 0.18288)
		(layer "In4.Cu")
		(net "M_B_CPU0_SB_DQ<3>")
	)
	(segment
		(start 303.280064 -228.666548)
		(end 301.952406 -228.666548)
		(width 0.18288)
		(layer "In4.Cu")
		(net "M_B_CPU0_SB_DQ<3>")
	)
	(segment
		(start 308.10708 -227.843588)
		(end 308.10708 -228.468682)
		(width 0.18288)
		(layer "In4.Cu")
		(net "M_B_CPU0_SB_DQ<3>")
	)
	(segment
		(start 332.344268 -236.272324)
		(end 331.739748 -236.272324)
		(width 0.088646)
		(layer "In4.Cu")
		(net "M_B_CPU0_SB_DQ<3>")
	)
	(segment
		(start 340.602824 -235.456222)
		(end 340.59114 -235.462826)
		(width 0.088646)
		(layer "In4.Cu")
		(net "M_B_CPU0_SB_DQ<3>")
	)
	(segment
		(start 300.800516 -229.17277)
		(end 299.904658 -229.17277)
		(width 0.18288)
		(layer "In4.Cu")
		(net "M_B_CPU0_SB_DQ<3>")
	)
	(segment
		(start 308.892448 -227.835968)
		(end 308.740048 -227.683568)
		(width 0.18288)
		(layer "In4.Cu")
		(net "M_B_CPU0_SB_DQ<3>")
	)
	(segment
		(start 301.952406 -228.666548)
		(end 301.282608 -229.336346)
		(width 0.18288)
		(layer "In4.Cu")
		(net "M_B_CPU0_SB_DQ<3>")
	)
	(segment
		(start 306.282344 -227.776532)
		(end 306.282344 -228.035104)
		(width 0.18288)
		(layer "In4.Cu")
		(net "M_B_CPU0_SB_DQ<3>")
	)
	(segment
		(start 332.481682 -236.13491)
		(end 332.344268 -236.272324)
		(width 0.088646)
		(layer "In4.Cu")
		(net "M_B_CPU0_SB_DQ<3>")
	)
	(segment
		(start 330.648564 -236.03839)
		(end 321.76085 -236.03839)
		(width 0.18288)
		(layer "In4.Cu")
		(net "M_B_CPU0_SB_DQ<3>")
	)
	(segment
		(start 311.059322 -227.88753)
		(end 310.734202 -227.88753)
		(width 0.18288)
		(layer "In4.Cu")
		(net "M_B_CPU0_SB_DQ<3>")
	)
	(segment
		(start 301.282608 -229.336346)
		(end 300.964092 -229.336346)
		(width 0.18288)
		(layer "In4.Cu")
		(net "M_B_CPU0_SB_DQ<3>")
	)
	(segment
		(start 303.83226 -229.218744)
		(end 303.280064 -228.666548)
		(width 0.18288)
		(layer "In4.Cu")
		(net "M_B_CPU0_SB_DQ<3>")
	)
	(segment
		(start 304.840132 -229.218744)
		(end 303.83226 -229.218744)
		(width 0.18288)
		(layer "In4.Cu")
		(net "M_B_CPU0_SB_DQ<3>")
	)
	(segment
		(start 307.413914 -228.443536)
		(end 307.413914 -227.698046)
		(width 0.18288)
		(layer "In4.Cu")
		(net "M_B_CPU0_SB_DQ<3>")
	)
	(segment
		(start 308.2671 -227.683568)
		(end 308.10708 -227.843588)
		(width 0.18288)
		(layer "In4.Cu")
		(net "M_B_CPU0_SB_DQ<3>")
	)
	(segment
		(start 310.368442 -229.19182)
		(end 309.569104 -229.19182)
		(width 0.18288)
		(layer "In4.Cu")
		(net "M_B_CPU0_SB_DQ<3>")
	)
	(segment
		(start 307.413914 -227.698046)
		(end 307.253894 -227.538026)
		(width 0.18288)
		(layer "In4.Cu")
		(net "M_B_CPU0_SB_DQ<3>")
	)
	(segment
		(start 339.531452 -235.554774)
		(end 339.466428 -235.620052)
		(width 0.088646)
		(layer "In4.Cu")
		(net "M_B_CPU0_SB_DQ<3>")
	)
	(segment
		(start 306.52085 -227.538026)
		(end 306.282344 -227.776532)
		(width 0.18288)
		(layer "In4.Cu")
		(net "M_B_CPU0_SB_DQ<3>")
	)
	(segment
		(start 308.892448 -228.515164)
		(end 308.892448 -227.835968)
		(width 0.18288)
		(layer "In4.Cu")
		(net "M_B_CPU0_SB_DQ<3>")
	)
	(segment
		(start 310.734202 -227.88753)
		(end 310.551322 -228.07041)
		(width 0.18288)
		(layer "In4.Cu")
		(net "M_B_CPU0_SB_DQ<3>")
	)
	(segment
		(start 339.24113 -235.99267)
		(end 339.235796 -235.998004)
		(width 0.088646)
		(layer "In4.Cu")
		(net "M_B_CPU0_SB_DQ<3>")
	)
	(segment
		(start 306.282344 -228.035104)
		(end 306.33797 -228.09073)
		(width 0.18288)
		(layer "In4.Cu")
		(net "M_B_CPU0_SB_DQ<3>")
	)
	(segment
		(start 331.505814 -236.03839)
		(end 330.648564 -236.03839)
		(width 0.088646)
		(layer "In4.Cu")
		(net "M_B_CPU0_SB_DQ<3>")
	)
	(segment
		(start 307.253894 -227.538026)
		(end 306.52085 -227.538026)
		(width 0.18288)
		(layer "In4.Cu")
		(net "M_B_CPU0_SB_DQ<3>")
	)
	(segment
		(start 312.26252 -229.19182)
		(end 311.425082 -229.19182)
		(width 0.18288)
		(layer "In4.Cu")
		(net "M_B_CPU0_SB_DQ<3>")
	)
	(segment
		(start 339.44179 -235.656628)
		(end 339.402928 -235.750608)
		(width 0.088646)
		(layer "In4.Cu")
		(net "M_B_CPU0_SB_DQ<3>")
	)
	(segment
		(start 310.551322 -228.07041)
		(end 310.551322 -229.00894)
		(width 0.18288)
		(layer "In4.Cu")
		(net "M_B_CPU0_SB_DQ<3>")
	)
	(segment
		(start 305.849274 -228.579426)
		(end 305.793648 -228.5238)
		(width 0.18288)
		(layer "In4.Cu")
		(net "M_B_CPU0_SB_DQ<3>")
	)
	(segment
		(start 311.242202 -228.07041)
		(end 311.059322 -227.88753)
		(width 0.18288)
		(layer "In4.Cu")
		(net "M_B_CPU0_SB_DQ<3>")
	)
	(segment
		(start 339.663024 -235.456222)
		(end 339.65134 -235.462826)
		(width 0.088646)
		(layer "In4.Cu")
		(net "M_B_CPU0_SB_DQ<3>")
	)
	(segment
		(start 311.425082 -229.19182)
		(end 311.242202 -229.00894)
		(width 0.18288)
		(layer "In4.Cu")
		(net "M_B_CPU0_SB_DQ<3>")
	)
	(segment
		(start 307.94706 -228.628702)
		(end 307.59908 -228.628702)
		(width 0.18288)
		(layer "In4.Cu")
		(net "M_B_CPU0_SB_DQ<3>")
	)
	(segment
		(start 305.535076 -228.5238)
		(end 304.840132 -229.218744)
		(width 0.18288)
		(layer "In4.Cu")
		(net "M_B_CPU0_SB_DQ<3>")
	)
	(segment
		(start 309.569104 -229.19182)
		(end 308.892448 -228.515164)
		(width 0.18288)
		(layer "In4.Cu")
		(net "M_B_CPU0_SB_DQ<3>")
	)
	(segment
		(start 331.739748 -236.272324)
		(end 331.505814 -236.03839)
		(width 0.088646)
		(layer "In4.Cu")
		(net "M_B_CPU0_SB_DQ<3>")
	)
	(segment
		(start 313.112404 -230.041704)
		(end 312.26252 -229.19182)
		(width 0.18288)
		(layer "In4.Cu")
		(net "M_B_CPU0_SB_DQ<3>")
	)
	(segment
		(start 338.721954 -236.111034)
		(end 338.717382 -236.108494)
		(width 0.088646)
		(layer "In4.Cu")
		(net "M_B_CPU0_SB_DQ<3>")
	)
	(segment
		(start 315.764164 -230.041704)
		(end 313.112404 -230.041704)
		(width 0.18288)
		(layer "In4.Cu")
		(net "M_B_CPU0_SB_DQ<3>")
	)
	(segment
		(start 341.724234 -235.783882)
		(end 341.72398 -235.783882)
		(width 0.088646)
		(layer "In4.Cu")
		(net "M_B_CPU0_SB_DQ<3>")
	)
	(segment
		(start 299.460666 -229.616762)
		(end 299.004482 -229.616762)
		(width 0.18288)
		(layer "In4.Cu")
		(net "M_B_CPU0_SB_DQ<3>")
	)
	(segment
		(start 300.964092 -229.336346)
		(end 300.800516 -229.17277)
		(width 0.18288)
		(layer "In4.Cu")
		(net "M_B_CPU0_SB_DQ<3>")
	)
	(segment
		(start 307.59908 -228.628702)
		(end 307.413914 -228.443536)
		(width 0.18288)
		(layer "In4.Cu")
		(net "M_B_CPU0_SB_DQ<3>")
	)
	(segment
		(start 336.272632 -236.108494)
		(end 336.272632 -236.10824)
		(width 0.088646)
		(layer "In4.Cu")
		(net "M_B_CPU0_SB_DQ<3>")
	)
	(segment
		(start 308.10708 -228.468682)
		(end 307.94706 -228.628702)
		(width 0.18288)
		(layer "In4.Cu")
		(net "M_B_CPU0_SB_DQ<3>")
	)
	(segment
		(start 306.107846 -228.579426)
		(end 305.849274 -228.579426)
		(width 0.18288)
		(layer "In4.Cu")
		(net "M_B_CPU0_SB_DQ<3>")
	)
	(segment
		(start 308.740048 -227.683568)
		(end 308.2671 -227.683568)
		(width 0.18288)
		(layer "In4.Cu")
		(net "M_B_CPU0_SB_DQ<3>")
	)
	(segment
		(start 336.842354 -236.111034)
		(end 336.837782 -236.108494)
		(width 0.088646)
		(layer "In4.Cu")
		(net "M_B_CPU0_SB_DQ<3>")
	)
	(segment
		(start 337.782154 -236.111034)
		(end 337.770216 -236.104176)
		(width 0.088646)
		(layer "In4.Cu")
		(net "M_B_CPU0_SB_DQ<3>")
	)
	(segment
		(start 321.76085 -236.03839)
		(end 315.764164 -230.041704)
		(width 0.18288)
		(layer "In4.Cu")
		(net "M_B_CPU0_SB_DQ<3>")
	)
	(segment
		(start 306.33797 -228.349302)
		(end 306.107846 -228.579426)
		(width 0.18288)
		(layer "In4.Cu")
		(net "M_B_CPU0_SB_DQ<3>")
	)
	(segment
		(start 336.837782 -236.108494)
		(end 336.83321 -236.1057)
		(width 0.088646)
		(layer "In4.Cu")
		(net "M_B_CPU0_SB_DQ<3>")
	)
	(segment
		(start 299.904658 -229.17277)
		(end 299.460666 -229.616762)
		(width 0.18288)
		(layer "In4.Cu")
		(net "M_B_CPU0_SB_DQ<3>")
	)
	(segment
		(start 305.793648 -228.5238)
		(end 305.535076 -228.5238)
		(width 0.18288)
		(layer "In4.Cu")
		(net "M_B_CPU0_SB_DQ<3>")
	)
	(arc
		(start 338.710016 -236.104176)
		(mid 338.430555 -236.032739)
		(end 338.152232 -236.108494)
		(width 0.088646)
		(layer "In4.Cu")
		(net "M_B_CPU0_SB_DQ<3>")
	)
	(arc
		(start 333.453232 -236.10824)
		(mid 333.266034 -236.158383)
		(end 333.078836 -236.10824)
		(width 0.088646)
		(layer "In4.Cu")
		(net "M_B_CPU0_SB_DQ<3>")
	)
	(arc
		(start 334.393032 -236.10824)
		(mid 334.205834 -236.158383)
		(end 334.018636 -236.10824)
		(width 0.088646)
		(layer "In4.Cu")
		(net "M_B_CPU0_SB_DQ<3>")
	)
	(arc
		(start 339.235796 -235.998004)
		(mid 339.167546 -236.057976)
		(end 339.092032 -236.108494)
		(width 0.088646)
		(layer "In4.Cu")
		(net "M_B_CPU0_SB_DQ<3>")
	)
	(arc
		(start 340.031832 -235.459524)
		(mid 339.847878 -235.409395)
		(end 339.663024 -235.456222)
		(width 0.088646)
		(layer "In4.Cu")
		(net "M_B_CPU0_SB_DQ<3>")
	)
	(arc
		(start 333.078836 -236.10824)
		(mid 332.820079 -236.032889)
		(end 332.55585 -236.085888)
		(width 0.088646)
		(layer "In4.Cu")
		(net "M_B_CPU0_SB_DQ<3>")
	)
	(arc
		(start 340.971632 -235.459524)
		(mid 340.787678 -235.409395)
		(end 340.602824 -235.456222)
		(width 0.088646)
		(layer "In4.Cu")
		(net "M_B_CPU0_SB_DQ<3>")
	)
	(arc
		(start 337.212432 -236.108494)
		(mid 337.027738 -236.158595)
		(end 336.842354 -236.111034)
		(width 0.088646)
		(layer "In4.Cu")
		(net "M_B_CPU0_SB_DQ<3>")
	)
	(arc
		(start 339.65134 -235.462826)
		(mid 339.588381 -235.504869)
		(end 339.531452 -235.554774)
		(width 0.088646)
		(layer "In4.Cu")
		(net "M_B_CPU0_SB_DQ<3>")
	)
	(arc
		(start 334.958436 -236.10824)
		(mid 334.675734 -236.032498)
		(end 334.393032 -236.10824)
		(width 0.088646)
		(layer "In4.Cu")
		(net "M_B_CPU0_SB_DQ<3>")
	)
	(arc
		(start 336.272632 -236.10824)
		(mid 336.085434 -236.158383)
		(end 335.898236 -236.10824)
		(width 0.088646)
		(layer "In4.Cu")
		(net "M_B_CPU0_SB_DQ<3>")
	)
	(arc
		(start 339.466428 -235.620052)
		(mid 339.452289 -235.637116)
		(end 339.44179 -235.656628)
		(width 0.088646)
		(layer "In4.Cu")
		(net "M_B_CPU0_SB_DQ<3>")
	)
	(arc
		(start 335.898236 -236.10824)
		(mid 335.615534 -236.032498)
		(end 335.332832 -236.10824)
		(width 0.088646)
		(layer "In4.Cu")
		(net "M_B_CPU0_SB_DQ<3>")
	)
	(arc
		(start 337.770216 -236.104176)
		(mid 337.490755 -236.032739)
		(end 337.212432 -236.108494)
		(width 0.088646)
		(layer "In4.Cu")
		(net "M_B_CPU0_SB_DQ<3>")
	)
	(arc
		(start 340.59114 -235.462826)
		(mid 340.311035 -235.535268)
		(end 340.031832 -235.459524)
		(width 0.088646)
		(layer "In4.Cu")
		(net "M_B_CPU0_SB_DQ<3>")
	)
	(arc
		(start 335.332832 -236.10824)
		(mid 335.145634 -236.158383)
		(end 334.958436 -236.10824)
		(width 0.088646)
		(layer "In4.Cu")
		(net "M_B_CPU0_SB_DQ<3>")
	)
	(arc
		(start 336.83321 -236.1057)
		(mid 336.552546 -236.032692)
		(end 336.272632 -236.108494)
		(width 0.088646)
		(layer "In4.Cu")
		(net "M_B_CPU0_SB_DQ<3>")
	)
	(arc
		(start 338.152232 -236.108494)
		(mid 337.967538 -236.158595)
		(end 337.782154 -236.111034)
		(width 0.088646)
		(layer "In4.Cu")
		(net "M_B_CPU0_SB_DQ<3>")
	)
	(arc
		(start 339.092032 -236.108494)
		(mid 338.907338 -236.158595)
		(end 338.721954 -236.111034)
		(width 0.088646)
		(layer "In4.Cu")
		(net "M_B_CPU0_SB_DQ<3>")
	)
	(arc
		(start 339.402928 -235.750608)
		(mid 339.333972 -235.879623)
		(end 339.24113 -235.99267)
		(width 0.088646)
		(layer "In4.Cu")
		(net "M_B_CPU0_SB_DQ<3>")
	)
	(arc
		(start 334.018636 -236.10824)
		(mid 333.735934 -236.032498)
		(end 333.453232 -236.10824)
		(width 0.088646)
		(layer "In4.Cu")
		(net "M_B_CPU0_SB_DQ<3>")
	)
	(arc
		(start 332.55585 -236.085888)
		(mid 332.516995 -236.107717)
		(end 332.481682 -236.13491)
		(width 0.088646)
		(layer "In4.Cu")
		(net "M_B_CPU0_SB_DQ<3>")
	)
	(arc
		(start 341.72398 -235.783882)
		(mid 341.539895 -235.759704)
		(end 341.36838 -235.688632)
		(width 0.088646)
		(layer "In4.Cu")
		(net "M_B_CPU0_SB_DQ<3>")
	)
	(segment
		(start 292.321488 -196.055742)
		(end 292.178994 -195.913248)
		(width 0.20066)
		(layer "F.Cu")
		(net "M_B_CPU0_SB_DQ<31>")
	)
	(segment
		(start 335.14538 -224.389696)
		(end 335.145634 -224.389442)
		(width 0.20066)
		(layer "F.Cu")
		(net "M_B_CPU0_SB_DQ<31>")
	)
	(segment
		(start 292.178994 -195.74256)
		(end 292.05301 -195.616576)
		(width 0.20066)
		(layer "F.Cu")
		(net "M_B_CPU0_SB_DQ<31>")
	)
	(segment
		(start 335.14538 -224.925382)
		(end 335.14538 -224.389696)
		(width 0.20066)
		(layer "F.Cu")
		(net "M_B_CPU0_SB_DQ<31>")
	)
	(segment
		(start 296.875962 -195.824094)
		(end 296.42943 -195.824094)
		(width 0.20066)
		(layer "F.Cu")
		(net "M_B_CPU0_SB_DQ<31>")
	)
	(segment
		(start 295.82237 -195.612258)
		(end 295.693846 -195.740782)
		(width 0.20066)
		(layer "F.Cu")
		(net "M_B_CPU0_SB_DQ<31>")
	)
	(segment
		(start 295.544748 -196.041518)
		(end 295.000426 -196.041518)
		(width 0.20066)
		(layer "F.Cu")
		(net "M_B_CPU0_SB_DQ<31>")
	)
	(segment
		(start 292.67531 -196.055742)
		(end 292.321488 -196.055742)
		(width 0.20066)
		(layer "F.Cu")
		(net "M_B_CPU0_SB_DQ<31>")
	)
	(segment
		(start 299.004482 -195.616576)
		(end 297.899582 -195.616576)
		(width 0.20066)
		(layer "F.Cu")
		(net "M_B_CPU0_SB_DQ<31>")
	)
	(segment
		(start 296.217594 -195.612258)
		(end 295.82237 -195.612258)
		(width 0.20066)
		(layer "F.Cu")
		(net "M_B_CPU0_SB_DQ<31>")
	)
	(segment
		(start 296.42943 -195.824094)
		(end 296.217594 -195.612258)
		(width 0.20066)
		(layer "F.Cu")
		(net "M_B_CPU0_SB_DQ<31>")
	)
	(segment
		(start 295.000426 -196.041518)
		(end 292.927532 -196.041518)
		(width 0.1016)
		(layer "F.Cu")
		(net "M_B_CPU0_SB_DQ<31>")
	)
	(segment
		(start 297.08348 -195.616576)
		(end 296.875962 -195.824094)
		(width 0.20066)
		(layer "F.Cu")
		(net "M_B_CPU0_SB_DQ<31>")
	)
	(segment
		(start 297.899582 -195.616576)
		(end 297.08348 -195.616576)
		(width 0.20066)
		(layer "F.Cu")
		(net "M_B_CPU0_SB_DQ<31>")
	)
	(segment
		(start 292.178994 -195.913248)
		(end 292.178994 -195.74256)
		(width 0.20066)
		(layer "F.Cu")
		(net "M_B_CPU0_SB_DQ<31>")
	)
	(segment
		(start 292.927532 -196.041518)
		(end 292.689534 -196.041518)
		(width 0.101854)
		(layer "F.Cu")
		(net "M_B_CPU0_SB_DQ<31>")
	)
	(segment
		(start 292.05301 -195.616576)
		(end 290.355782 -195.616576)
		(width 0.20066)
		(layer "F.Cu")
		(net "M_B_CPU0_SB_DQ<31>")
	)
	(segment
		(start 292.689534 -196.041518)
		(end 292.67531 -196.055742)
		(width 0.101854)
		(layer "F.Cu")
		(net "M_B_CPU0_SB_DQ<31>")
	)
	(segment
		(start 295.693846 -195.740782)
		(end 295.693846 -195.89242)
		(width 0.20066)
		(layer "F.Cu")
		(net "M_B_CPU0_SB_DQ<31>")
	)
	(segment
		(start 295.693846 -195.89242)
		(end 295.544748 -196.041518)
		(width 0.20066)
		(layer "F.Cu")
		(net "M_B_CPU0_SB_DQ<31>")
	)
	(segment
		(start 310.6674 -196.169026)
		(end 309.32374 -196.169026)
		(width 0.18288)
		(layer "In4.Cu")
		(net "M_B_CPU0_SB_DQ<31>")
	)
	(segment
		(start 312.994294 -196.169026)
		(end 312.540142 -196.169026)
		(width 0.18288)
		(layer "In4.Cu")
		(net "M_B_CPU0_SB_DQ<31>")
	)
	(segment
		(start 309.14086 -195.986146)
		(end 309.14086 -195.908422)
		(width 0.18288)
		(layer "In4.Cu")
		(net "M_B_CPU0_SB_DQ<31>")
	)
	(segment
		(start 315.3664 -196.954648)
		(end 314.284106 -195.872354)
		(width 0.18288)
		(layer "In4.Cu")
		(net "M_B_CPU0_SB_DQ<31>")
	)
	(segment
		(start 305.60645 -196.380354)
		(end 305.199034 -196.380354)
		(width 0.18288)
		(layer "In4.Cu")
		(net "M_B_CPU0_SB_DQ<31>")
	)
	(segment
		(start 303.590198 -195.804536)
		(end 303.271428 -196.123306)
		(width 0.18288)
		(layer "In4.Cu")
		(net "M_B_CPU0_SB_DQ<31>")
	)
	(segment
		(start 306.159662 -195.827142)
		(end 305.60645 -196.380354)
		(width 0.18288)
		(layer "In4.Cu")
		(net "M_B_CPU0_SB_DQ<31>")
	)
	(segment
		(start 331.60081 -221.208092)
		(end 331.163422 -220.770704)
		(width 0.088646)
		(layer "In4.Cu")
		(net "M_B_CPU0_SB_DQ<31>")
	)
	(segment
		(start 307.555138 -196.169026)
		(end 307.213254 -195.827142)
		(width 0.18288)
		(layer "In4.Cu")
		(net "M_B_CPU0_SB_DQ<31>")
	)
	(segment
		(start 312.540142 -196.169026)
		(end 312.234072 -195.862956)
		(width 0.18288)
		(layer "In4.Cu")
		(net "M_B_CPU0_SB_DQ<31>")
	)
	(segment
		(start 305.199034 -196.380354)
		(end 304.623216 -195.804536)
		(width 0.18288)
		(layer "In4.Cu")
		(net "M_B_CPU0_SB_DQ<31>")
	)
	(segment
		(start 332.992222 -221.628462)
		(end 332.983332 -221.623382)
		(width 0.088646)
		(layer "In4.Cu")
		(net "M_B_CPU0_SB_DQ<31>")
	)
	(segment
		(start 333.64043 -222.769176)
		(end 333.64043 -222.761556)
		(width 0.088646)
		(layer "In4.Cu")
		(net "M_B_CPU0_SB_DQ<31>")
	)
	(segment
		(start 330.648564 -220.770704)
		(end 329.618086 -220.770704)
		(width 0.18288)
		(layer "In4.Cu")
		(net "M_B_CPU0_SB_DQ<31>")
	)
	(segment
		(start 313.290966 -195.872354)
		(end 312.994294 -196.169026)
		(width 0.18288)
		(layer "In4.Cu")
		(net "M_B_CPU0_SB_DQ<31>")
	)
	(segment
		(start 335.145634 -224.389442)
		(end 334.98917 -224.118424)
		(width 0.088646)
		(layer "In4.Cu")
		(net "M_B_CPU0_SB_DQ<31>")
	)
	(segment
		(start 304.623216 -195.804536)
		(end 303.590198 -195.804536)
		(width 0.18288)
		(layer "In4.Cu")
		(net "M_B_CPU0_SB_DQ<31>")
	)
	(segment
		(start 299.511212 -196.123306)
		(end 299.004482 -195.616576)
		(width 0.18288)
		(layer "In4.Cu")
		(net "M_B_CPU0_SB_DQ<31>")
	)
	(segment
		(start 316.455806 -199.584818)
		(end 315.3664 -196.954648)
		(width 0.18288)
		(layer "In4.Cu")
		(net "M_B_CPU0_SB_DQ<31>")
	)
	(segment
		(start 307.213254 -195.827142)
		(end 306.159662 -195.827142)
		(width 0.18288)
		(layer "In4.Cu")
		(net "M_B_CPU0_SB_DQ<31>")
	)
	(segment
		(start 333.170784 -221.963234)
		(end 333.170784 -221.94774)
		(width 0.088646)
		(layer "In4.Cu")
		(net "M_B_CPU0_SB_DQ<31>")
	)
	(segment
		(start 326.169782 -217.3224)
		(end 320.496184 -203.625196)
		(width 0.18288)
		(layer "In4.Cu")
		(net "M_B_CPU0_SB_DQ<31>")
	)
	(segment
		(start 312.234072 -195.862956)
		(end 310.97347 -195.862956)
		(width 0.18288)
		(layer "In4.Cu")
		(net "M_B_CPU0_SB_DQ<31>")
	)
	(segment
		(start 301.967138 -196.123306)
		(end 301.6758 -195.831968)
		(width 0.18288)
		(layer "In4.Cu")
		(net "M_B_CPU0_SB_DQ<31>")
	)
	(segment
		(start 308.44998 -195.986146)
		(end 308.2671 -196.169026)
		(width 0.18288)
		(layer "In4.Cu")
		(net "M_B_CPU0_SB_DQ<31>")
	)
	(segment
		(start 308.44998 -195.908422)
		(end 308.44998 -195.986146)
		(width 0.18288)
		(layer "In4.Cu")
		(net "M_B_CPU0_SB_DQ<31>")
	)
	(segment
		(start 308.2671 -196.169026)
		(end 307.555138 -196.169026)
		(width 0.18288)
		(layer "In4.Cu")
		(net "M_B_CPU0_SB_DQ<31>")
	)
	(segment
		(start 310.97347 -195.862956)
		(end 310.6674 -196.169026)
		(width 0.18288)
		(layer "In4.Cu")
		(net "M_B_CPU0_SB_DQ<31>")
	)
	(segment
		(start 300.979078 -196.123306)
		(end 299.511212 -196.123306)
		(width 0.18288)
		(layer "In4.Cu")
		(net "M_B_CPU0_SB_DQ<31>")
	)
	(segment
		(start 309.32374 -196.169026)
		(end 309.14086 -195.986146)
		(width 0.18288)
		(layer "In4.Cu")
		(net "M_B_CPU0_SB_DQ<31>")
	)
	(segment
		(start 333.932022 -223.256348)
		(end 333.923132 -223.251268)
		(width 0.088646)
		(layer "In4.Cu")
		(net "M_B_CPU0_SB_DQ<31>")
	)
	(segment
		(start 309.14086 -195.908422)
		(end 308.95798 -195.725542)
		(width 0.18288)
		(layer "In4.Cu")
		(net "M_B_CPU0_SB_DQ<31>")
	)
	(segment
		(start 303.271428 -196.123306)
		(end 301.967138 -196.123306)
		(width 0.18288)
		(layer "In4.Cu")
		(net "M_B_CPU0_SB_DQ<31>")
	)
	(segment
		(start 331.163422 -220.770704)
		(end 330.648564 -220.770704)
		(width 0.088646)
		(layer "In4.Cu")
		(net "M_B_CPU0_SB_DQ<31>")
	)
	(segment
		(start 334.98917 -224.118424)
		(end 334.900016 -224.094548)
		(width 0.088646)
		(layer "In4.Cu")
		(net "M_B_CPU0_SB_DQ<31>")
	)
	(segment
		(start 308.63286 -195.725542)
		(end 308.44998 -195.908422)
		(width 0.18288)
		(layer "In4.Cu")
		(net "M_B_CPU0_SB_DQ<31>")
	)
	(segment
		(start 301.6758 -195.831968)
		(end 301.270416 -195.831968)
		(width 0.18288)
		(layer "In4.Cu")
		(net "M_B_CPU0_SB_DQ<31>")
	)
	(segment
		(start 329.618086 -220.770704)
		(end 326.169782 -217.3224)
		(width 0.18288)
		(layer "In4.Cu")
		(net "M_B_CPU0_SB_DQ<31>")
	)
	(segment
		(start 320.496184 -203.625196)
		(end 316.455806 -199.584818)
		(width 0.18288)
		(layer "In4.Cu")
		(net "M_B_CPU0_SB_DQ<31>")
	)
	(segment
		(start 334.110584 -223.585532)
		(end 334.110584 -223.575626)
		(width 0.088646)
		(layer "In4.Cu")
		(net "M_B_CPU0_SB_DQ<31>")
	)
	(segment
		(start 333.461868 -222.442278)
		(end 333.452978 -222.437198)
		(width 0.088646)
		(layer "In4.Cu")
		(net "M_B_CPU0_SB_DQ<31>")
	)
	(segment
		(start 331.926692 -221.534228)
		(end 331.60081 -221.208092)
		(width 0.088646)
		(layer "In4.Cu")
		(net "M_B_CPU0_SB_DQ<31>")
	)
	(segment
		(start 308.95798 -195.725542)
		(end 308.63286 -195.725542)
		(width 0.18288)
		(layer "In4.Cu")
		(net "M_B_CPU0_SB_DQ<31>")
	)
	(segment
		(start 314.284106 -195.872354)
		(end 313.290966 -195.872354)
		(width 0.18288)
		(layer "In4.Cu")
		(net "M_B_CPU0_SB_DQ<31>")
	)
	(segment
		(start 301.270416 -195.831968)
		(end 300.979078 -196.123306)
		(width 0.18288)
		(layer "In4.Cu")
		(net "M_B_CPU0_SB_DQ<31>")
	)
	(arc
		(start 334.900016 -224.094548)
		(mid 334.643017 -224.139995)
		(end 334.393032 -224.065084)
		(width 0.088646)
		(layer "In4.Cu")
		(net "M_B_CPU0_SB_DQ<31>")
	)
	(arc
		(start 331.979524 -221.580456)
		(mid 331.952388 -221.558164)
		(end 331.926692 -221.534228)
		(width 0.088646)
		(layer "In4.Cu")
		(net "M_B_CPU0_SB_DQ<31>")
	)
	(arc
		(start 332.043532 -221.623382)
		(mid 332.010796 -221.603011)
		(end 331.979524 -221.580456)
		(width 0.088646)
		(layer "In4.Cu")
		(net "M_B_CPU0_SB_DQ<31>")
	)
	(arc
		(start 334.393032 -224.065084)
		(mid 334.188697 -223.862479)
		(end 334.110584 -223.585532)
		(width 0.088646)
		(layer "In4.Cu")
		(net "M_B_CPU0_SB_DQ<31>")
	)
	(arc
		(start 332.608936 -221.623382)
		(mid 332.326234 -221.699158)
		(end 332.043532 -221.623382)
		(width 0.088646)
		(layer "In4.Cu")
		(net "M_B_CPU0_SB_DQ<31>")
	)
	(arc
		(start 334.110584 -223.575626)
		(mid 334.062905 -223.392726)
		(end 333.932022 -223.256348)
		(width 0.088646)
		(layer "In4.Cu")
		(net "M_B_CPU0_SB_DQ<31>")
	)
	(arc
		(start 333.64043 -222.761556)
		(mid 333.592751 -222.578656)
		(end 333.461868 -222.442278)
		(width 0.088646)
		(layer "In4.Cu")
		(net "M_B_CPU0_SB_DQ<31>")
	)
	(arc
		(start 333.452978 -222.437198)
		(mid 333.250155 -222.236967)
		(end 333.170784 -221.963234)
		(width 0.088646)
		(layer "In4.Cu")
		(net "M_B_CPU0_SB_DQ<31>")
	)
	(arc
		(start 333.170784 -221.94774)
		(mid 333.123105 -221.76484)
		(end 332.992222 -221.628462)
		(width 0.088646)
		(layer "In4.Cu")
		(net "M_B_CPU0_SB_DQ<31>")
	)
	(arc
		(start 333.923132 -223.251268)
		(mid 333.71806 -223.047589)
		(end 333.64043 -222.769176)
		(width 0.088646)
		(layer "In4.Cu")
		(net "M_B_CPU0_SB_DQ<31>")
	)
	(arc
		(start 332.983332 -221.623382)
		(mid 332.796134 -221.573239)
		(end 332.608936 -221.623382)
		(width 0.088646)
		(layer "In4.Cu")
		(net "M_B_CPU0_SB_DQ<31>")
	)
	(segment
		(start 295.777158 -197.03542)
		(end 295.633394 -196.891656)
		(width 0.20066)
		(layer "F.Cu")
		(net "M_B_CPU0_SB_DQ<30>")
	)
	(segment
		(start 295.777158 -197.361048)
		(end 295.777158 -197.03542)
		(width 0.20066)
		(layer "F.Cu")
		(net "M_B_CPU0_SB_DQ<30>")
	)
	(segment
		(start 292.940486 -196.891656)
		(end 292.68547 -196.891656)
		(width 0.101854)
		(layer "F.Cu")
		(net "M_B_CPU0_SB_DQ<30>")
	)
	(segment
		(start 299.004482 -197.316598)
		(end 297.899582 -197.316598)
		(width 0.20066)
		(layer "F.Cu")
		(net "M_B_CPU0_SB_DQ<30>")
	)
	(segment
		(start 333.26578 -224.925382)
		(end 333.26578 -224.389442)
		(width 0.20066)
		(layer "F.Cu")
		(net "M_B_CPU0_SB_DQ<30>")
	)
	(segment
		(start 296.373042 -197.528434)
		(end 295.944544 -197.528434)
		(width 0.20066)
		(layer "F.Cu")
		(net "M_B_CPU0_SB_DQ<30>")
	)
	(segment
		(start 291.937948 -196.881496)
		(end 291.502846 -197.316598)
		(width 0.20066)
		(layer "F.Cu")
		(net "M_B_CPU0_SB_DQ<30>")
	)
	(segment
		(start 292.67531 -196.881496)
		(end 291.937948 -196.881496)
		(width 0.20066)
		(layer "F.Cu")
		(net "M_B_CPU0_SB_DQ<30>")
	)
	(segment
		(start 295.633394 -196.891656)
		(end 295.000426 -196.891656)
		(width 0.20066)
		(layer "F.Cu")
		(net "M_B_CPU0_SB_DQ<30>")
	)
	(segment
		(start 292.68547 -196.891656)
		(end 292.67531 -196.881496)
		(width 0.101854)
		(layer "F.Cu")
		(net "M_B_CPU0_SB_DQ<30>")
	)
	(segment
		(start 291.502846 -197.316598)
		(end 290.355782 -197.316598)
		(width 0.20066)
		(layer "F.Cu")
		(net "M_B_CPU0_SB_DQ<30>")
	)
	(segment
		(start 296.584878 -197.316598)
		(end 296.373042 -197.528434)
		(width 0.20066)
		(layer "F.Cu")
		(net "M_B_CPU0_SB_DQ<30>")
	)
	(segment
		(start 297.899582 -197.316598)
		(end 296.584878 -197.316598)
		(width 0.20066)
		(layer "F.Cu")
		(net "M_B_CPU0_SB_DQ<30>")
	)
	(segment
		(start 295.944544 -197.528434)
		(end 295.777158 -197.361048)
		(width 0.20066)
		(layer "F.Cu")
		(net "M_B_CPU0_SB_DQ<30>")
	)
	(segment
		(start 295.000426 -196.891656)
		(end 292.940486 -196.891656)
		(width 0.1016)
		(layer "F.Cu")
		(net "M_B_CPU0_SB_DQ<30>")
	)
	(segment
		(start 312.127138 -197.41007)
		(end 311.68721 -197.41007)
		(width 0.18288)
		(layer "In4.Cu")
		(net "M_B_CPU0_SB_DQ<30>")
	)
	(segment
		(start 301.065692 -198.580756)
		(end 300.882812 -198.763636)
		(width 0.18288)
		(layer "In4.Cu")
		(net "M_B_CPU0_SB_DQ<30>")
	)
	(segment
		(start 333.170784 -223.59112)
		(end 333.170784 -223.575626)
		(width 0.088646)
		(layer "In4.Cu")
		(net "M_B_CPU0_SB_DQ<30>")
	)
	(segment
		(start 308.27726 -197.78218)
		(end 307.16093 -197.78218)
		(width 0.18288)
		(layer "In4.Cu")
		(net "M_B_CPU0_SB_DQ<30>")
	)
	(segment
		(start 331.631036 -222.51289)
		(end 330.88453 -221.766384)
		(width 0.088646)
		(layer "In4.Cu")
		(net "M_B_CPU0_SB_DQ<30>")
	)
	(segment
		(start 305.116738 -197.884542)
		(end 305.116738 -197.720204)
		(width 0.18288)
		(layer "In4.Cu")
		(net "M_B_CPU0_SB_DQ<30>")
	)
	(segment
		(start 299.501052 -197.813168)
		(end 299.004482 -197.316598)
		(width 0.18288)
		(layer "In4.Cu")
		(net "M_B_CPU0_SB_DQ<30>")
	)
	(segment
		(start 332.522068 -222.442278)
		(end 332.513178 -222.437198)
		(width 0.088646)
		(layer "In4.Cu")
		(net "M_B_CPU0_SB_DQ<30>")
	)
	(segment
		(start 302.447452 -197.996048)
		(end 302.447452 -198.432928)
		(width 0.18288)
		(layer "In4.Cu")
		(net "M_B_CPU0_SB_DQ<30>")
	)
	(segment
		(start 301.939452 -198.624444)
		(end 301.756572 -198.441564)
		(width 0.18288)
		(layer "In4.Cu")
		(net "M_B_CPU0_SB_DQ<30>")
	)
	(segment
		(start 330.648564 -221.766384)
		(end 329.128628 -221.766384)
		(width 0.18288)
		(layer "In4.Cu")
		(net "M_B_CPU0_SB_DQ<30>")
	)
	(segment
		(start 313.983624 -198.799196)
		(end 313.50712 -198.322692)
		(width 0.18288)
		(layer "In4.Cu")
		(net "M_B_CPU0_SB_DQ<30>")
	)
	(segment
		(start 302.630332 -197.813168)
		(end 302.447452 -197.996048)
		(width 0.18288)
		(layer "In4.Cu")
		(net "M_B_CPU0_SB_DQ<30>")
	)
	(segment
		(start 332.70063 -222.77578)
		(end 332.70063 -222.761556)
		(width 0.088646)
		(layer "In4.Cu")
		(net "M_B_CPU0_SB_DQ<30>")
	)
	(segment
		(start 300.374812 -198.554848)
		(end 300.374812 -197.996048)
		(width 0.18288)
		(layer "In4.Cu")
		(net "M_B_CPU0_SB_DQ<30>")
	)
	(segment
		(start 300.374812 -197.996048)
		(end 300.191932 -197.813168)
		(width 0.18288)
		(layer "In4.Cu")
		(net "M_B_CPU0_SB_DQ<30>")
	)
	(segment
		(start 305.990498 -197.537324)
		(end 305.807618 -197.720204)
		(width 0.18288)
		(layer "In4.Cu")
		(net "M_B_CPU0_SB_DQ<30>")
	)
	(segment
		(start 300.191932 -197.813168)
		(end 299.501052 -197.813168)
		(width 0.18288)
		(layer "In4.Cu")
		(net "M_B_CPU0_SB_DQ<30>")
	)
	(segment
		(start 307.16093 -197.78218)
		(end 306.916074 -197.537324)
		(width 0.18288)
		(layer "In4.Cu")
		(net "M_B_CPU0_SB_DQ<30>")
	)
	(segment
		(start 311.174892 -197.661022)
		(end 311.064402 -197.771512)
		(width 0.18288)
		(layer "In4.Cu")
		(net "M_B_CPU0_SB_DQ<30>")
	)
	(segment
		(start 325.379588 -218.017344)
		(end 319.668144 -204.228954)
		(width 0.18288)
		(layer "In4.Cu")
		(net "M_B_CPU0_SB_DQ<30>")
	)
	(segment
		(start 305.807618 -197.884542)
		(end 305.624738 -198.067422)
		(width 0.18288)
		(layer "In4.Cu")
		(net "M_B_CPU0_SB_DQ<30>")
	)
	(segment
		(start 333.26578 -224.389442)
		(end 333.422244 -224.118424)
		(width 0.088646)
		(layer "In4.Cu")
		(net "M_B_CPU0_SB_DQ<30>")
	)
	(segment
		(start 302.255936 -198.624444)
		(end 301.939452 -198.624444)
		(width 0.18288)
		(layer "In4.Cu")
		(net "M_B_CPU0_SB_DQ<30>")
	)
	(segment
		(start 332.992222 -223.256348)
		(end 332.983332 -223.251268)
		(width 0.088646)
		(layer "In4.Cu")
		(net "M_B_CPU0_SB_DQ<30>")
	)
	(segment
		(start 329.128628 -221.766384)
		(end 325.379588 -218.017344)
		(width 0.18288)
		(layer "In4.Cu")
		(net "M_B_CPU0_SB_DQ<30>")
	)
	(segment
		(start 301.756572 -197.996048)
		(end 301.573692 -197.813168)
		(width 0.18288)
		(layer "In4.Cu")
		(net "M_B_CPU0_SB_DQ<30>")
	)
	(segment
		(start 315.18987 -199.75068)
		(end 315.18987 -199.555608)
		(width 0.18288)
		(layer "In4.Cu")
		(net "M_B_CPU0_SB_DQ<30>")
	)
	(segment
		(start 313.50712 -198.322692)
		(end 313.50712 -197.883272)
		(width 0.18288)
		(layer "In4.Cu")
		(net "M_B_CPU0_SB_DQ<30>")
	)
	(segment
		(start 311.436258 -197.661022)
		(end 311.174892 -197.661022)
		(width 0.18288)
		(layer "In4.Cu")
		(net "M_B_CPU0_SB_DQ<30>")
	)
	(segment
		(start 311.68721 -197.41007)
		(end 311.436258 -197.661022)
		(width 0.18288)
		(layer "In4.Cu")
		(net "M_B_CPU0_SB_DQ<30>")
	)
	(segment
		(start 300.5836 -198.763636)
		(end 300.374812 -198.554848)
		(width 0.18288)
		(layer "In4.Cu")
		(net "M_B_CPU0_SB_DQ<30>")
	)
	(segment
		(start 301.756572 -198.441564)
		(end 301.756572 -197.996048)
		(width 0.18288)
		(layer "In4.Cu")
		(net "M_B_CPU0_SB_DQ<30>")
	)
	(segment
		(start 303.967134 -197.813168)
		(end 302.630332 -197.813168)
		(width 0.18288)
		(layer "In4.Cu")
		(net "M_B_CPU0_SB_DQ<30>")
	)
	(segment
		(start 309.631334 -197.771512)
		(end 309.249318 -197.389496)
		(width 0.18288)
		(layer "In4.Cu")
		(net "M_B_CPU0_SB_DQ<30>")
	)
	(segment
		(start 314.732924 -199.035416)
		(end 314.474352 -199.035162)
		(width 0.18288)
		(layer "In4.Cu")
		(net "M_B_CPU0_SB_DQ<30>")
	)
	(segment
		(start 301.248572 -197.813168)
		(end 301.065692 -197.996048)
		(width 0.18288)
		(layer "In4.Cu")
		(net "M_B_CPU0_SB_DQ<30>")
	)
	(segment
		(start 312.37809 -197.661022)
		(end 312.127138 -197.41007)
		(width 0.18288)
		(layer "In4.Cu")
		(net "M_B_CPU0_SB_DQ<30>")
	)
	(segment
		(start 300.882812 -198.763636)
		(end 300.5836 -198.763636)
		(width 0.18288)
		(layer "In4.Cu")
		(net "M_B_CPU0_SB_DQ<30>")
	)
	(segment
		(start 304.242978 -197.537324)
		(end 303.967134 -197.813168)
		(width 0.18288)
		(layer "In4.Cu")
		(net "M_B_CPU0_SB_DQ<30>")
	)
	(segment
		(start 315.190124 -199.297544)
		(end 314.927996 -199.035416)
		(width 0.18288)
		(layer "In4.Cu")
		(net "M_B_CPU0_SB_DQ<30>")
	)
	(segment
		(start 305.807618 -197.720204)
		(end 305.807618 -197.884542)
		(width 0.18288)
		(layer "In4.Cu")
		(net "M_B_CPU0_SB_DQ<30>")
	)
	(segment
		(start 315.18987 -199.555608)
		(end 315.190124 -199.297544)
		(width 0.18288)
		(layer "In4.Cu")
		(net "M_B_CPU0_SB_DQ<30>")
	)
	(segment
		(start 305.624738 -198.067422)
		(end 305.299618 -198.067422)
		(width 0.18288)
		(layer "In4.Cu")
		(net "M_B_CPU0_SB_DQ<30>")
	)
	(segment
		(start 305.116738 -197.720204)
		(end 304.933858 -197.537324)
		(width 0.18288)
		(layer "In4.Cu")
		(net "M_B_CPU0_SB_DQ<30>")
	)
	(segment
		(start 314.238386 -198.799196)
		(end 313.983624 -198.799196)
		(width 0.18288)
		(layer "In4.Cu")
		(net "M_B_CPU0_SB_DQ<30>")
	)
	(segment
		(start 305.299618 -198.067422)
		(end 305.116738 -197.884542)
		(width 0.18288)
		(layer "In4.Cu")
		(net "M_B_CPU0_SB_DQ<30>")
	)
	(segment
		(start 313.50712 -197.883272)
		(end 313.28487 -197.661022)
		(width 0.18288)
		(layer "In4.Cu")
		(net "M_B_CPU0_SB_DQ<30>")
	)
	(segment
		(start 311.064402 -197.771512)
		(end 309.631334 -197.771512)
		(width 0.18288)
		(layer "In4.Cu")
		(net "M_B_CPU0_SB_DQ<30>")
	)
	(segment
		(start 306.916074 -197.537324)
		(end 305.990498 -197.537324)
		(width 0.18288)
		(layer "In4.Cu")
		(net "M_B_CPU0_SB_DQ<30>")
	)
	(segment
		(start 314.927996 -199.035416)
		(end 314.732924 -199.035416)
		(width 0.18288)
		(layer "In4.Cu")
		(net "M_B_CPU0_SB_DQ<30>")
	)
	(segment
		(start 333.422244 -224.118424)
		(end 333.398114 -224.02927)
		(width 0.088646)
		(layer "In4.Cu")
		(net "M_B_CPU0_SB_DQ<30>")
	)
	(segment
		(start 314.474352 -199.035162)
		(end 314.238386 -198.799196)
		(width 0.18288)
		(layer "In4.Cu")
		(net "M_B_CPU0_SB_DQ<30>")
	)
	(segment
		(start 331.856588 -222.51289)
		(end 331.631036 -222.51289)
		(width 0.088646)
		(layer "In4.Cu")
		(net "M_B_CPU0_SB_DQ<30>")
	)
	(segment
		(start 308.669944 -197.389496)
		(end 308.27726 -197.78218)
		(width 0.18288)
		(layer "In4.Cu")
		(net "M_B_CPU0_SB_DQ<30>")
	)
	(segment
		(start 304.933858 -197.537324)
		(end 304.242978 -197.537324)
		(width 0.18288)
		(layer "In4.Cu")
		(net "M_B_CPU0_SB_DQ<30>")
	)
	(segment
		(start 313.28487 -197.661022)
		(end 312.37809 -197.661022)
		(width 0.18288)
		(layer "In4.Cu")
		(net "M_B_CPU0_SB_DQ<30>")
	)
	(segment
		(start 301.065692 -197.996048)
		(end 301.065692 -198.580756)
		(width 0.18288)
		(layer "In4.Cu")
		(net "M_B_CPU0_SB_DQ<30>")
	)
	(segment
		(start 302.447452 -198.432928)
		(end 302.255936 -198.624444)
		(width 0.18288)
		(layer "In4.Cu")
		(net "M_B_CPU0_SB_DQ<30>")
	)
	(segment
		(start 319.668144 -204.228954)
		(end 315.18987 -199.75068)
		(width 0.18288)
		(layer "In4.Cu")
		(net "M_B_CPU0_SB_DQ<30>")
	)
	(segment
		(start 330.88453 -221.766384)
		(end 330.648564 -221.766384)
		(width 0.088646)
		(layer "In4.Cu")
		(net "M_B_CPU0_SB_DQ<30>")
	)
	(segment
		(start 301.573692 -197.813168)
		(end 301.248572 -197.813168)
		(width 0.18288)
		(layer "In4.Cu")
		(net "M_B_CPU0_SB_DQ<30>")
	)
	(segment
		(start 309.249318 -197.389496)
		(end 308.669944 -197.389496)
		(width 0.18288)
		(layer "In4.Cu")
		(net "M_B_CPU0_SB_DQ<30>")
	)
	(arc
		(start 332.70063 -222.761556)
		(mid 332.652951 -222.578656)
		(end 332.522068 -222.442278)
		(width 0.088646)
		(layer "In4.Cu")
		(net "M_B_CPU0_SB_DQ<30>")
	)
	(arc
		(start 331.89291 -222.511874)
		(mid 331.874757 -222.512677)
		(end 331.856588 -222.51289)
		(width 0.088646)
		(layer "In4.Cu")
		(net "M_B_CPU0_SB_DQ<30>")
	)
	(arc
		(start 332.513178 -222.437198)
		(mid 332.32598 -222.387055)
		(end 332.138782 -222.437198)
		(width 0.088646)
		(layer "In4.Cu")
		(net "M_B_CPU0_SB_DQ<30>")
	)
	(arc
		(start 332.983332 -223.251268)
		(mid 332.779851 -223.050464)
		(end 332.70063 -222.77578)
		(width 0.088646)
		(layer "In4.Cu")
		(net "M_B_CPU0_SB_DQ<30>")
	)
	(arc
		(start 333.398114 -224.02927)
		(mid 333.234082 -223.836321)
		(end 333.170784 -223.59112)
		(width 0.088646)
		(layer "In4.Cu")
		(net "M_B_CPU0_SB_DQ<30>")
	)
	(arc
		(start 332.138782 -222.437198)
		(mid 332.020151 -222.488718)
		(end 331.89291 -222.511874)
		(width 0.088646)
		(layer "In4.Cu")
		(net "M_B_CPU0_SB_DQ<30>")
	)
	(arc
		(start 333.170784 -223.575626)
		(mid 333.123105 -223.392726)
		(end 332.992222 -223.256348)
		(width 0.088646)
		(layer "In4.Cu")
		(net "M_B_CPU0_SB_DQ<30>")
	)
	(segment
		(start 292.68547 -230.891842)
		(end 292.67531 -230.881682)
		(width 0.101854)
		(layer "F.Cu")
		(net "M_B_CPU0_SB_DQ<2>")
	)
	(segment
		(start 295.000426 -230.891842)
		(end 292.940486 -230.891842)
		(width 0.1016)
		(layer "F.Cu")
		(net "M_B_CPU0_SB_DQ<2>")
	)
	(segment
		(start 292.940486 -230.891842)
		(end 292.68547 -230.891842)
		(width 0.101854)
		(layer "F.Cu")
		(net "M_B_CPU0_SB_DQ<2>")
	)
	(segment
		(start 299.004482 -231.316784)
		(end 297.899582 -231.316784)
		(width 0.20066)
		(layer "F.Cu")
		(net "M_B_CPU0_SB_DQ<2>")
	)
	(segment
		(start 341.254334 -237.133892)
		(end 341.25408 -237.133638)
		(width 0.20066)
		(layer "F.Cu")
		(net "M_B_CPU0_SB_DQ<2>")
	)
	(segment
		(start 296.584878 -231.316784)
		(end 296.373042 -231.52862)
		(width 0.20066)
		(layer "F.Cu")
		(net "M_B_CPU0_SB_DQ<2>")
	)
	(segment
		(start 291.502846 -231.316784)
		(end 290.355782 -231.316784)
		(width 0.20066)
		(layer "F.Cu")
		(net "M_B_CPU0_SB_DQ<2>")
	)
	(segment
		(start 292.67531 -230.881682)
		(end 291.937948 -230.881682)
		(width 0.20066)
		(layer "F.Cu")
		(net "M_B_CPU0_SB_DQ<2>")
	)
	(segment
		(start 296.373042 -231.52862)
		(end 295.944544 -231.52862)
		(width 0.20066)
		(layer "F.Cu")
		(net "M_B_CPU0_SB_DQ<2>")
	)
	(segment
		(start 341.25408 -237.133638)
		(end 341.25408 -236.597952)
		(width 0.20066)
		(layer "F.Cu")
		(net "M_B_CPU0_SB_DQ<2>")
	)
	(segment
		(start 295.633394 -230.891842)
		(end 295.000426 -230.891842)
		(width 0.20066)
		(layer "F.Cu")
		(net "M_B_CPU0_SB_DQ<2>")
	)
	(segment
		(start 297.899582 -231.316784)
		(end 296.584878 -231.316784)
		(width 0.20066)
		(layer "F.Cu")
		(net "M_B_CPU0_SB_DQ<2>")
	)
	(segment
		(start 295.777158 -231.361234)
		(end 295.777158 -231.035606)
		(width 0.20066)
		(layer "F.Cu")
		(net "M_B_CPU0_SB_DQ<2>")
	)
	(segment
		(start 295.944544 -231.52862)
		(end 295.777158 -231.361234)
		(width 0.20066)
		(layer "F.Cu")
		(net "M_B_CPU0_SB_DQ<2>")
	)
	(segment
		(start 295.777158 -231.035606)
		(end 295.633394 -230.891842)
		(width 0.20066)
		(layer "F.Cu")
		(net "M_B_CPU0_SB_DQ<2>")
	)
	(segment
		(start 291.937948 -230.881682)
		(end 291.502846 -231.316784)
		(width 0.20066)
		(layer "F.Cu")
		(net "M_B_CPU0_SB_DQ<2>")
	)
	(segment
		(start 319.19672 -235.827316)
		(end 318.742568 -235.827316)
		(width 0.18288)
		(layer "In4.Cu")
		(net "M_B_CPU0_SB_DQ<2>")
	)
	(segment
		(start 332.89113 -237.411768)
		(end 332.89113 -237.427262)
		(width 0.088646)
		(layer "In4.Cu")
		(net "M_B_CPU0_SB_DQ<2>")
	)
	(segment
		(start 338.166964 -237.096046)
		(end 338.152232 -237.08741)
		(width 0.088646)
		(layer "In4.Cu")
		(net "M_B_CPU0_SB_DQ<2>")
	)
	(segment
		(start 318.480948 -235.565696)
		(end 318.480948 -235.111544)
		(width 0.18288)
		(layer "In4.Cu")
		(net "M_B_CPU0_SB_DQ<2>")
	)
	(segment
		(start 317.503556 -234.134152)
		(end 317.241936 -233.872532)
		(width 0.18288)
		(layer "In4.Cu")
		(net "M_B_CPU0_SB_DQ<2>")
	)
	(segment
		(start 301.311056 -231.058212)
		(end 301.128176 -230.875332)
		(width 0.18288)
		(layer "In4.Cu")
		(net "M_B_CPU0_SB_DQ<2>")
	)
	(segment
		(start 337.227164 -237.096046)
		(end 337.212432 -237.08741)
		(width 0.088646)
		(layer "In4.Cu")
		(net "M_B_CPU0_SB_DQ<2>")
	)
	(segment
		(start 314.378594 -232.80624)
		(end 314.195714 -232.62336)
		(width 0.18288)
		(layer "In4.Cu")
		(net "M_B_CPU0_SB_DQ<2>")
	)
	(segment
		(start 301.493936 -231.438958)
		(end 301.311056 -231.256078)
		(width 0.18288)
		(layer "In4.Cu")
		(net "M_B_CPU0_SB_DQ<2>")
	)
	(segment
		(start 301.311056 -231.256078)
		(end 301.311056 -231.058212)
		(width 0.18288)
		(layer "In4.Cu")
		(net "M_B_CPU0_SB_DQ<2>")
	)
	(segment
		(start 319.45834 -236.088936)
		(end 319.19672 -235.827316)
		(width 0.18288)
		(layer "In4.Cu")
		(net "M_B_CPU0_SB_DQ<2>")
	)
	(segment
		(start 302.82896 -230.875332)
		(end 302.184816 -230.875332)
		(width 0.18288)
		(layer "In4.Cu")
		(net "M_B_CPU0_SB_DQ<2>")
	)
	(segment
		(start 314.195714 -232.62336)
		(end 313.046364 -232.62336)
		(width 0.18288)
		(layer "In4.Cu")
		(net "M_B_CPU0_SB_DQ<2>")
	)
	(segment
		(start 305.637946 -230.65613)
		(end 305.256438 -231.037638)
		(width 0.18288)
		(layer "In4.Cu")
		(net "M_B_CPU0_SB_DQ<2>")
	)
	(segment
		(start 311.538874 -231.739694)
		(end 309.910988 -231.739694)
		(width 0.18288)
		(layer "In4.Cu")
		(net "M_B_CPU0_SB_DQ<2>")
	)
	(segment
		(start 302.001936 -231.256078)
		(end 301.819056 -231.438958)
		(width 0.18288)
		(layer "In4.Cu")
		(net "M_B_CPU0_SB_DQ<2>")
	)
	(segment
		(start 311.721246 -231.557322)
		(end 311.538874 -231.739694)
		(width 0.18288)
		(layer "In4.Cu")
		(net "M_B_CPU0_SB_DQ<2>")
	)
	(segment
		(start 302.001936 -231.058212)
		(end 302.001936 -231.256078)
		(width 0.18288)
		(layer "In4.Cu")
		(net "M_B_CPU0_SB_DQ<2>")
	)
	(segment
		(start 301.128176 -230.875332)
		(end 299.958506 -230.875332)
		(width 0.18288)
		(layer "In4.Cu")
		(net "M_B_CPU0_SB_DQ<2>")
	)
	(segment
		(start 315.992764 -232.62336)
		(end 315.252354 -232.62336)
		(width 0.18288)
		(layer "In4.Cu")
		(net "M_B_CPU0_SB_DQ<2>")
	)
	(segment
		(start 316.526164 -233.15676)
		(end 315.992764 -232.62336)
		(width 0.18288)
		(layer "In4.Cu")
		(net "M_B_CPU0_SB_DQ<2>")
	)
	(segment
		(start 339.663024 -237.083854)
		(end 339.657182 -237.087156)
		(width 0.088646)
		(layer "In4.Cu")
		(net "M_B_CPU0_SB_DQ<2>")
	)
	(segment
		(start 307.018944 -230.737918)
		(end 306.88915 -230.867712)
		(width 0.18288)
		(layer "In4.Cu")
		(net "M_B_CPU0_SB_DQ<2>")
	)
	(segment
		(start 305.075082 -231.618028)
		(end 303.571656 -231.618028)
		(width 0.18288)
		(layer "In4.Cu")
		(net "M_B_CPU0_SB_DQ<2>")
	)
	(segment
		(start 334.958182 -237.08741)
		(end 334.947768 -237.093506)
		(width 0.088646)
		(layer "In4.Cu")
		(net "M_B_CPU0_SB_DQ<2>")
	)
	(segment
		(start 314.378594 -233.212386)
		(end 314.378594 -232.80624)
		(width 0.18288)
		(layer "In4.Cu")
		(net "M_B_CPU0_SB_DQ<2>")
	)
	(segment
		(start 301.819056 -231.438958)
		(end 301.493936 -231.438958)
		(width 0.18288)
		(layer "In4.Cu")
		(net "M_B_CPU0_SB_DQ<2>")
	)
	(segment
		(start 334.018636 -237.08741)
		(end 334.008222 -237.093506)
		(width 0.088646)
		(layer "In4.Cu")
		(net "M_B_CPU0_SB_DQ<2>")
	)
	(segment
		(start 303.571656 -231.618028)
		(end 302.82896 -230.875332)
		(width 0.18288)
		(layer "In4.Cu")
		(net "M_B_CPU0_SB_DQ<2>")
	)
	(segment
		(start 308.965092 -231.655366)
		(end 308.7243 -231.414574)
		(width 0.18288)
		(layer "In4.Cu")
		(net "M_B_CPU0_SB_DQ<2>")
	)
	(segment
		(start 317.241936 -233.872532)
		(end 316.787784 -233.872532)
		(width 0.18288)
		(layer "In4.Cu")
		(net "M_B_CPU0_SB_DQ<2>")
	)
	(segment
		(start 315.252354 -232.62336)
		(end 315.069474 -232.80624)
		(width 0.18288)
		(layer "In4.Cu")
		(net "M_B_CPU0_SB_DQ<2>")
	)
	(segment
		(start 331.856334 -237.85068)
		(end 331.583792 -237.85068)
		(width 0.088646)
		(layer "In4.Cu")
		(net "M_B_CPU0_SB_DQ<2>")
	)
	(segment
		(start 309.910988 -231.739694)
		(end 309.798212 -231.692958)
		(width 0.18288)
		(layer "In4.Cu")
		(net "M_B_CPU0_SB_DQ<2>")
	)
	(segment
		(start 339.092032 -237.087156)
		(end 339.092032 -237.08741)
		(width 0.088646)
		(layer "In4.Cu")
		(net "M_B_CPU0_SB_DQ<2>")
	)
	(segment
		(start 306.88915 -231.477566)
		(end 306.72913 -231.637586)
		(width 0.18288)
		(layer "In4.Cu")
		(net "M_B_CPU0_SB_DQ<2>")
	)
	(segment
		(start 308.7243 -231.414574)
		(end 308.7243 -231.078278)
		(width 0.18288)
		(layer "In4.Cu")
		(net "M_B_CPU0_SB_DQ<2>")
	)
	(segment
		(start 314.572142 -233.405934)
		(end 314.378594 -233.212386)
		(width 0.18288)
		(layer "In4.Cu")
		(net "M_B_CPU0_SB_DQ<2>")
	)
	(segment
		(start 306.38115 -231.637586)
		(end 306.18303 -231.439466)
		(width 0.18288)
		(layer "In4.Cu")
		(net "M_B_CPU0_SB_DQ<2>")
	)
	(segment
		(start 317.765176 -234.849924)
		(end 317.503556 -234.588304)
		(width 0.18288)
		(layer "In4.Cu")
		(net "M_B_CPU0_SB_DQ<2>")
	)
	(segment
		(start 317.503556 -234.588304)
		(end 317.503556 -234.134152)
		(width 0.18288)
		(layer "In4.Cu")
		(net "M_B_CPU0_SB_DQ<2>")
	)
	(segment
		(start 306.88915 -230.867712)
		(end 306.88915 -231.477566)
		(width 0.18288)
		(layer "In4.Cu")
		(net "M_B_CPU0_SB_DQ<2>")
	)
	(segment
		(start 335.898236 -237.08741)
		(end 335.887822 -237.093506)
		(width 0.088646)
		(layer "In4.Cu")
		(net "M_B_CPU0_SB_DQ<2>")
	)
	(segment
		(start 313.046364 -232.62336)
		(end 311.980326 -231.557322)
		(width 0.18288)
		(layer "In4.Cu")
		(net "M_B_CPU0_SB_DQ<2>")
	)
	(segment
		(start 305.256438 -231.037638)
		(end 305.256438 -231.436672)
		(width 0.18288)
		(layer "In4.Cu")
		(net "M_B_CPU0_SB_DQ<2>")
	)
	(segment
		(start 320.174112 -236.804708)
		(end 319.71996 -236.804708)
		(width 0.18288)
		(layer "In4.Cu")
		(net "M_B_CPU0_SB_DQ<2>")
	)
	(segment
		(start 309.707534 -231.655366)
		(end 308.965092 -231.655366)
		(width 0.18288)
		(layer "In4.Cu")
		(net "M_B_CPU0_SB_DQ<2>")
	)
	(segment
		(start 306.18303 -231.439466)
		(end 306.18303 -230.809292)
		(width 0.18288)
		(layer "In4.Cu")
		(net "M_B_CPU0_SB_DQ<2>")
	)
	(segment
		(start 341.25408 -236.597952)
		(end 340.488524 -237.017306)
		(width 0.088646)
		(layer "In4.Cu")
		(net "M_B_CPU0_SB_DQ<2>")
	)
	(segment
		(start 305.256438 -231.436672)
		(end 305.075082 -231.618028)
		(width 0.18288)
		(layer "In4.Cu")
		(net "M_B_CPU0_SB_DQ<2>")
	)
	(segment
		(start 319.45834 -236.543088)
		(end 319.45834 -236.088936)
		(width 0.18288)
		(layer "In4.Cu")
		(net "M_B_CPU0_SB_DQ<2>")
	)
	(segment
		(start 332.058264 -237.909862)
		(end 332.043532 -237.901226)
		(width 0.088646)
		(layer "In4.Cu")
		(net "M_B_CPU0_SB_DQ<2>")
	)
	(segment
		(start 315.069474 -232.80624)
		(end 315.069474 -233.223054)
		(width 0.18288)
		(layer "In4.Cu")
		(net "M_B_CPU0_SB_DQ<2>")
	)
	(segment
		(start 306.72913 -231.637586)
		(end 306.38115 -231.637586)
		(width 0.18288)
		(layer "In4.Cu")
		(net "M_B_CPU0_SB_DQ<2>")
	)
	(segment
		(start 320.901314 -237.53191)
		(end 320.174112 -236.804708)
		(width 0.18288)
		(layer "In4.Cu")
		(net "M_B_CPU0_SB_DQ<2>")
	)
	(segment
		(start 314.886594 -233.405934)
		(end 314.572142 -233.405934)
		(width 0.18288)
		(layer "In4.Cu")
		(net "M_B_CPU0_SB_DQ<2>")
	)
	(segment
		(start 306.029868 -230.65613)
		(end 305.637946 -230.65613)
		(width 0.18288)
		(layer "In4.Cu")
		(net "M_B_CPU0_SB_DQ<2>")
	)
	(segment
		(start 308.7243 -231.078278)
		(end 308.38394 -230.737918)
		(width 0.18288)
		(layer "In4.Cu")
		(net "M_B_CPU0_SB_DQ<2>")
	)
	(segment
		(start 318.219328 -234.849924)
		(end 317.765176 -234.849924)
		(width 0.18288)
		(layer "In4.Cu")
		(net "M_B_CPU0_SB_DQ<2>")
	)
	(segment
		(start 302.184816 -230.875332)
		(end 302.001936 -231.058212)
		(width 0.18288)
		(layer "In4.Cu")
		(net "M_B_CPU0_SB_DQ<2>")
	)
	(segment
		(start 331.265022 -237.53191)
		(end 331.004164 -237.53191)
		(width 0.088646)
		(layer "In4.Cu")
		(net "M_B_CPU0_SB_DQ<2>")
	)
	(segment
		(start 318.742568 -235.827316)
		(end 318.480948 -235.565696)
		(width 0.18288)
		(layer "In4.Cu")
		(net "M_B_CPU0_SB_DQ<2>")
	)
	(segment
		(start 306.18303 -230.809292)
		(end 306.029868 -230.65613)
		(width 0.18288)
		(layer "In4.Cu")
		(net "M_B_CPU0_SB_DQ<2>")
	)
	(segment
		(start 308.38394 -230.737918)
		(end 307.018944 -230.737918)
		(width 0.18288)
		(layer "In4.Cu")
		(net "M_B_CPU0_SB_DQ<2>")
	)
	(segment
		(start 309.798212 -231.692958)
		(end 309.707534 -231.655366)
		(width 0.18288)
		(layer "In4.Cu")
		(net "M_B_CPU0_SB_DQ<2>")
	)
	(segment
		(start 299.958506 -230.875332)
		(end 299.517054 -231.316784)
		(width 0.18288)
		(layer "In4.Cu")
		(net "M_B_CPU0_SB_DQ<2>")
	)
	(segment
		(start 311.980326 -231.557322)
		(end 311.721246 -231.557322)
		(width 0.18288)
		(layer "In4.Cu")
		(net "M_B_CPU0_SB_DQ<2>")
	)
	(segment
		(start 315.069474 -233.223054)
		(end 314.886594 -233.405934)
		(width 0.18288)
		(layer "In4.Cu")
		(net "M_B_CPU0_SB_DQ<2>")
	)
	(segment
		(start 299.517054 -231.316784)
		(end 299.004482 -231.316784)
		(width 0.18288)
		(layer "In4.Cu")
		(net "M_B_CPU0_SB_DQ<2>")
	)
	(segment
		(start 316.787784 -233.872532)
		(end 316.526164 -233.610912)
		(width 0.18288)
		(layer "In4.Cu")
		(net "M_B_CPU0_SB_DQ<2>")
	)
	(segment
		(start 318.480948 -235.111544)
		(end 318.219328 -234.849924)
		(width 0.18288)
		(layer "In4.Cu")
		(net "M_B_CPU0_SB_DQ<2>")
	)
	(segment
		(start 333.078582 -237.08741)
		(end 333.069692 -237.09249)
		(width 0.088646)
		(layer "In4.Cu")
		(net "M_B_CPU0_SB_DQ<2>")
	)
	(segment
		(start 319.71996 -236.804708)
		(end 319.45834 -236.543088)
		(width 0.18288)
		(layer "In4.Cu")
		(net "M_B_CPU0_SB_DQ<2>")
	)
	(segment
		(start 339.657182 -237.087156)
		(end 339.65134 -237.090712)
		(width 0.088646)
		(layer "In4.Cu")
		(net "M_B_CPU0_SB_DQ<2>")
	)
	(segment
		(start 331.583792 -237.85068)
		(end 331.265022 -237.53191)
		(width 0.088646)
		(layer "In4.Cu")
		(net "M_B_CPU0_SB_DQ<2>")
	)
	(segment
		(start 316.526164 -233.610912)
		(end 316.526164 -233.15676)
		(width 0.18288)
		(layer "In4.Cu")
		(net "M_B_CPU0_SB_DQ<2>")
	)
	(segment
		(start 331.004164 -237.53191)
		(end 320.901314 -237.53191)
		(width 0.18288)
		(layer "In4.Cu")
		(net "M_B_CPU0_SB_DQ<2>")
	)
	(arc
		(start 336.272632 -237.08741)
		(mid 336.085434 -237.037233)
		(end 335.898236 -237.08741)
		(width 0.088646)
		(layer "In4.Cu")
		(net "M_B_CPU0_SB_DQ<2>")
	)
	(arc
		(start 332.89113 -237.427262)
		(mid 332.81176 -237.700996)
		(end 332.608936 -237.901226)
		(width 0.088646)
		(layer "In4.Cu")
		(net "M_B_CPU0_SB_DQ<2>")
	)
	(arc
		(start 332.043532 -237.901226)
		(mid 331.95326 -237.863627)
		(end 331.856334 -237.85068)
		(width 0.088646)
		(layer "In4.Cu")
		(net "M_B_CPU0_SB_DQ<2>")
	)
	(arc
		(start 334.947768 -237.093506)
		(mid 334.66959 -237.163229)
		(end 334.393032 -237.08741)
		(width 0.088646)
		(layer "In4.Cu")
		(net "M_B_CPU0_SB_DQ<2>")
	)
	(arc
		(start 333.069692 -237.09249)
		(mid 332.938778 -237.22885)
		(end 332.89113 -237.411768)
		(width 0.088646)
		(layer "In4.Cu")
		(net "M_B_CPU0_SB_DQ<2>")
	)
	(arc
		(start 336.838036 -237.08741)
		(mid 336.555334 -237.163186)
		(end 336.272632 -237.08741)
		(width 0.088646)
		(layer "In4.Cu")
		(net "M_B_CPU0_SB_DQ<2>")
	)
	(arc
		(start 340.488524 -237.017306)
		(mid 340.447912 -237.035854)
		(end 340.404958 -237.04804)
		(width 0.088646)
		(layer "In4.Cu")
		(net "M_B_CPU0_SB_DQ<2>")
	)
	(arc
		(start 338.717636 -237.08741)
		(mid 338.443437 -237.163245)
		(end 338.166964 -237.096046)
		(width 0.088646)
		(layer "In4.Cu")
		(net "M_B_CPU0_SB_DQ<2>")
	)
	(arc
		(start 340.404958 -237.04804)
		(mid 340.163378 -237.071003)
		(end 339.922104 -237.044992)
		(width 0.088646)
		(layer "In4.Cu")
		(net "M_B_CPU0_SB_DQ<2>")
	)
	(arc
		(start 335.887822 -237.093506)
		(mid 335.60939 -237.163352)
		(end 335.332578 -237.08741)
		(width 0.088646)
		(layer "In4.Cu")
		(net "M_B_CPU0_SB_DQ<2>")
	)
	(arc
		(start 339.922104 -237.044992)
		(mid 339.789057 -237.04104)
		(end 339.663024 -237.083854)
		(width 0.088646)
		(layer "In4.Cu")
		(net "M_B_CPU0_SB_DQ<2>")
	)
	(arc
		(start 337.212432 -237.08741)
		(mid 337.025234 -237.037233)
		(end 336.838036 -237.08741)
		(width 0.088646)
		(layer "In4.Cu")
		(net "M_B_CPU0_SB_DQ<2>")
	)
	(arc
		(start 332.608936 -237.901226)
		(mid 332.334737 -237.977061)
		(end 332.058264 -237.909862)
		(width 0.088646)
		(layer "In4.Cu")
		(net "M_B_CPU0_SB_DQ<2>")
	)
	(arc
		(start 334.393032 -237.08741)
		(mid 334.205834 -237.037267)
		(end 334.018636 -237.08741)
		(width 0.088646)
		(layer "In4.Cu")
		(net "M_B_CPU0_SB_DQ<2>")
	)
	(arc
		(start 339.092032 -237.08741)
		(mid 338.904834 -237.037233)
		(end 338.717636 -237.08741)
		(width 0.088646)
		(layer "In4.Cu")
		(net "M_B_CPU0_SB_DQ<2>")
	)
	(arc
		(start 338.152232 -237.08741)
		(mid 337.965034 -237.037233)
		(end 337.777836 -237.08741)
		(width 0.088646)
		(layer "In4.Cu")
		(net "M_B_CPU0_SB_DQ<2>")
	)
	(arc
		(start 334.008222 -237.093506)
		(mid 333.72979 -237.163352)
		(end 333.452978 -237.08741)
		(width 0.088646)
		(layer "In4.Cu")
		(net "M_B_CPU0_SB_DQ<2>")
	)
	(arc
		(start 339.65134 -237.090712)
		(mid 339.371205 -237.163028)
		(end 339.092032 -237.087156)
		(width 0.088646)
		(layer "In4.Cu")
		(net "M_B_CPU0_SB_DQ<2>")
	)
	(arc
		(start 333.452978 -237.08741)
		(mid 333.26578 -237.037267)
		(end 333.078582 -237.08741)
		(width 0.088646)
		(layer "In4.Cu")
		(net "M_B_CPU0_SB_DQ<2>")
	)
	(arc
		(start 337.777836 -237.08741)
		(mid 337.503637 -237.163245)
		(end 337.227164 -237.096046)
		(width 0.088646)
		(layer "In4.Cu")
		(net "M_B_CPU0_SB_DQ<2>")
	)
	(arc
		(start 335.332578 -237.08741)
		(mid 335.14538 -237.037267)
		(end 334.958182 -237.08741)
		(width 0.088646)
		(layer "In4.Cu")
		(net "M_B_CPU0_SB_DQ<2>")
	)
	(segment
		(start 334.675734 -224.111566)
		(end 334.675734 -223.575626)
		(width 0.20066)
		(layer "F.Cu")
		(net "M_B_CPU0_SB_DQ<29>")
	)
	(segment
		(start 291.735256 -196.041772)
		(end 291.556694 -196.041772)
		(width 0.20066)
		(layer "F.Cu")
		(net "M_B_CPU0_SB_DQ<29>")
	)
	(segment
		(start 292.160198 -196.466714)
		(end 291.735256 -196.041772)
		(width 0.20066)
		(layer "F.Cu")
		(net "M_B_CPU0_SB_DQ<29>")
	)
	(segment
		(start 294.904414 -196.466714)
		(end 293.799514 -196.466714)
		(width 0.20066)
		(layer "F.Cu")
		(net "M_B_CPU0_SB_DQ<29>")
	)
	(segment
		(start 288.46018 -196.195442)
		(end 288.46018 -196.52361)
		(width 0.20066)
		(layer "F.Cu")
		(net "M_B_CPU0_SB_DQ<29>")
	)
	(segment
		(start 293.799514 -196.466714)
		(end 292.160198 -196.466714)
		(width 0.20066)
		(layer "F.Cu")
		(net "M_B_CPU0_SB_DQ<29>")
	)
	(segment
		(start 287.589976 -196.466714)
		(end 286.255714 -196.466714)
		(width 0.20066)
		(layer "F.Cu")
		(net "M_B_CPU0_SB_DQ<29>")
	)
	(segment
		(start 287.801304 -196.678042)
		(end 287.589976 -196.466714)
		(width 0.20066)
		(layer "F.Cu")
		(net "M_B_CPU0_SB_DQ<29>")
	)
	(segment
		(start 289.240468 -196.041772)
		(end 289.231578 -196.032882)
		(width 0.1016)
		(layer "F.Cu")
		(net "M_B_CPU0_SB_DQ<29>")
	)
	(segment
		(start 291.556694 -196.041772)
		(end 291.225986 -196.041772)
		(width 0.101854)
		(layer "F.Cu")
		(net "M_B_CPU0_SB_DQ<29>")
	)
	(segment
		(start 291.225986 -196.041772)
		(end 289.240468 -196.041772)
		(width 0.1016)
		(layer "F.Cu")
		(net "M_B_CPU0_SB_DQ<29>")
	)
	(segment
		(start 288.62274 -196.032882)
		(end 288.46018 -196.195442)
		(width 0.20066)
		(layer "F.Cu")
		(net "M_B_CPU0_SB_DQ<29>")
	)
	(segment
		(start 288.305748 -196.678042)
		(end 287.801304 -196.678042)
		(width 0.20066)
		(layer "F.Cu")
		(net "M_B_CPU0_SB_DQ<29>")
	)
	(segment
		(start 289.231578 -196.032882)
		(end 288.62274 -196.032882)
		(width 0.20066)
		(layer "F.Cu")
		(net "M_B_CPU0_SB_DQ<29>")
	)
	(segment
		(start 288.46018 -196.52361)
		(end 288.305748 -196.678042)
		(width 0.20066)
		(layer "F.Cu")
		(net "M_B_CPU0_SB_DQ<29>")
	)
	(segment
		(start 334.018636 -223.085914)
		(end 334.009746 -223.080834)
		(width 0.088646)
		(layer "In4.Cu")
		(net "M_B_CPU0_SB_DQ<29>")
	)
	(segment
		(start 326.518016 -216.860882)
		(end 320.906902 -203.314808)
		(width 0.18288)
		(layer "In4.Cu")
		(net "M_B_CPU0_SB_DQ<29>")
	)
	(segment
		(start 316.882272 -199.290178)
		(end 315.757052 -196.57314)
		(width 0.18288)
		(layer "In4.Cu")
		(net "M_B_CPU0_SB_DQ<29>")
	)
	(segment
		(start 298.82592 -195.191126)
		(end 297.983656 -195.191126)
		(width 0.18288)
		(layer "In4.Cu")
		(net "M_B_CPU0_SB_DQ<29>")
	)
	(segment
		(start 299.023532 -195.194936)
		(end 298.82973 -195.194936)
		(width 0.18288)
		(layer "In4.Cu")
		(net "M_B_CPU0_SB_DQ<29>")
	)
	(segment
		(start 333.548736 -222.272098)
		(end 333.539846 -222.267018)
		(width 0.088646)
		(layer "In4.Cu")
		(net "M_B_CPU0_SB_DQ<29>")
	)
	(segment
		(start 329.929998 -220.272864)
		(end 326.518016 -216.860882)
		(width 0.18288)
		(layer "In4.Cu")
		(net "M_B_CPU0_SB_DQ<29>")
	)
	(segment
		(start 297.983656 -195.191126)
		(end 294.904414 -196.466714)
		(width 0.18288)
		(layer "In4.Cu")
		(net "M_B_CPU0_SB_DQ<29>")
	)
	(segment
		(start 315.757052 -196.57314)
		(end 314.3758 -195.191888)
		(width 0.18288)
		(layer "In4.Cu")
		(net "M_B_CPU0_SB_DQ<29>")
	)
	(segment
		(start 334.488536 -223.899984)
		(end 334.479646 -223.894904)
		(width 0.088646)
		(layer "In4.Cu")
		(net "M_B_CPU0_SB_DQ<29>")
	)
	(segment
		(start 333.554832 -222.275654)
		(end 333.548736 -222.272098)
		(width 0.088646)
		(layer "In4.Cu")
		(net "M_B_CPU0_SB_DQ<29>")
	)
	(segment
		(start 334.301084 -223.575626)
		(end 334.301084 -223.557084)
		(width 0.088646)
		(layer "In4.Cu")
		(net "M_B_CPU0_SB_DQ<29>")
	)
	(segment
		(start 298.82973 -195.194936)
		(end 298.82592 -195.191126)
		(width 0.18288)
		(layer "In4.Cu")
		(net "M_B_CPU0_SB_DQ<29>")
	)
	(segment
		(start 330.648564 -220.272864)
		(end 329.929998 -220.272864)
		(width 0.18288)
		(layer "In4.Cu")
		(net "M_B_CPU0_SB_DQ<29>")
	)
	(segment
		(start 334.832198 -223.846644)
		(end 334.811116 -223.924622)
		(width 0.088646)
		(layer "In4.Cu")
		(net "M_B_CPU0_SB_DQ<29>")
	)
	(segment
		(start 334.675734 -223.575626)
		(end 334.832198 -223.846644)
		(width 0.088646)
		(layer "In4.Cu")
		(net "M_B_CPU0_SB_DQ<29>")
	)
	(segment
		(start 332.061058 -221.3991)
		(end 330.934822 -220.272864)
		(width 0.088646)
		(layer "In4.Cu")
		(net "M_B_CPU0_SB_DQ<29>")
	)
	(segment
		(start 320.906902 -203.314808)
		(end 316.882272 -199.290178)
		(width 0.18288)
		(layer "In4.Cu")
		(net "M_B_CPU0_SB_DQ<29>")
	)
	(segment
		(start 330.934822 -220.272864)
		(end 330.648564 -220.272864)
		(width 0.088646)
		(layer "In4.Cu")
		(net "M_B_CPU0_SB_DQ<29>")
	)
	(segment
		(start 333.361284 -221.94774)
		(end 333.361284 -221.937834)
		(width 0.088646)
		(layer "In4.Cu")
		(net "M_B_CPU0_SB_DQ<29>")
	)
	(segment
		(start 314.3758 -195.191888)
		(end 299.02658 -195.191888)
		(width 0.18288)
		(layer "In4.Cu")
		(net "M_B_CPU0_SB_DQ<29>")
	)
	(segment
		(start 299.02658 -195.191888)
		(end 299.023532 -195.194936)
		(width 0.18288)
		(layer "In4.Cu")
		(net "M_B_CPU0_SB_DQ<29>")
	)
	(arc
		(start 334.811116 -223.924622)
		(mid 334.64702 -223.948969)
		(end 334.488536 -223.899984)
		(width 0.088646)
		(layer "In4.Cu")
		(net "M_B_CPU0_SB_DQ<29>")
	)
	(arc
		(start 332.139036 -221.458282)
		(mid 332.098106 -221.431249)
		(end 332.061058 -221.3991)
		(width 0.088646)
		(layer "In4.Cu")
		(net "M_B_CPU0_SB_DQ<29>")
	)
	(arc
		(start 332.513432 -221.458282)
		(mid 332.326234 -221.508425)
		(end 332.139036 -221.458282)
		(width 0.088646)
		(layer "In4.Cu")
		(net "M_B_CPU0_SB_DQ<29>")
	)
	(arc
		(start 333.539846 -222.267018)
		(mid 333.408932 -222.130658)
		(end 333.361284 -221.94774)
		(width 0.088646)
		(layer "In4.Cu")
		(net "M_B_CPU0_SB_DQ<29>")
	)
	(arc
		(start 333.361284 -221.937834)
		(mid 333.283173 -221.660885)
		(end 333.078836 -221.458282)
		(width 0.088646)
		(layer "In4.Cu")
		(net "M_B_CPU0_SB_DQ<29>")
	)
	(arc
		(start 334.479646 -223.894904)
		(mid 334.348732 -223.758544)
		(end 334.301084 -223.575626)
		(width 0.088646)
		(layer "In4.Cu")
		(net "M_B_CPU0_SB_DQ<29>")
	)
	(arc
		(start 334.301084 -223.557084)
		(mid 334.220922 -223.284895)
		(end 334.018636 -223.085914)
		(width 0.088646)
		(layer "In4.Cu")
		(net "M_B_CPU0_SB_DQ<29>")
	)
	(arc
		(start 333.078836 -221.458282)
		(mid 332.796134 -221.382506)
		(end 332.513432 -221.458282)
		(width 0.088646)
		(layer "In4.Cu")
		(net "M_B_CPU0_SB_DQ<29>")
	)
	(arc
		(start 334.009746 -223.080834)
		(mid 333.878832 -222.944474)
		(end 333.831184 -222.761556)
		(width 0.088646)
		(layer "In4.Cu")
		(net "M_B_CPU0_SB_DQ<29>")
	)
	(arc
		(start 333.831184 -222.761556)
		(mid 333.757268 -222.482054)
		(end 333.554832 -222.275654)
		(width 0.088646)
		(layer "In4.Cu")
		(net "M_B_CPU0_SB_DQ<29>")
	)
	(segment
		(start 287.589976 -198.166736)
		(end 286.255714 -198.166736)
		(width 0.20066)
		(layer "F.Cu")
		(net "M_B_CPU0_SB_DQ<28>")
	)
	(segment
		(start 288.46018 -198.232776)
		(end 288.28746 -198.405496)
		(width 0.20066)
		(layer "F.Cu")
		(net "M_B_CPU0_SB_DQ<28>")
	)
	(segment
		(start 288.28746 -198.405496)
		(end 287.828736 -198.405496)
		(width 0.20066)
		(layer "F.Cu")
		(net "M_B_CPU0_SB_DQ<28>")
	)
	(segment
		(start 288.46018 -197.943216)
		(end 288.46018 -198.232776)
		(width 0.20066)
		(layer "F.Cu")
		(net "M_B_CPU0_SB_DQ<28>")
	)
	(segment
		(start 289.48761 -197.741794)
		(end 289.239706 -197.741794)
		(width 0.101854)
		(layer "F.Cu")
		(net "M_B_CPU0_SB_DQ<28>")
	)
	(segment
		(start 289.231578 -197.733666)
		(end 288.66973 -197.733666)
		(width 0.20066)
		(layer "F.Cu")
		(net "M_B_CPU0_SB_DQ<28>")
	)
	(segment
		(start 292.005512 -197.741794)
		(end 291.556694 -197.741794)
		(width 0.20066)
		(layer "F.Cu")
		(net "M_B_CPU0_SB_DQ<28>")
	)
	(segment
		(start 287.828736 -198.405496)
		(end 287.589976 -198.166736)
		(width 0.20066)
		(layer "F.Cu")
		(net "M_B_CPU0_SB_DQ<28>")
	)
	(segment
		(start 293.799514 -198.166736)
		(end 292.430454 -198.166736)
		(width 0.20066)
		(layer "F.Cu")
		(net "M_B_CPU0_SB_DQ<28>")
	)
	(segment
		(start 333.735934 -224.111566)
		(end 333.735934 -223.575626)
		(width 0.20066)
		(layer "F.Cu")
		(net "M_B_CPU0_SB_DQ<28>")
	)
	(segment
		(start 289.239706 -197.741794)
		(end 289.231578 -197.733666)
		(width 0.101854)
		(layer "F.Cu")
		(net "M_B_CPU0_SB_DQ<28>")
	)
	(segment
		(start 292.430454 -198.166736)
		(end 292.005512 -197.741794)
		(width 0.20066)
		(layer "F.Cu")
		(net "M_B_CPU0_SB_DQ<28>")
	)
	(segment
		(start 288.66973 -197.733666)
		(end 288.46018 -197.943216)
		(width 0.20066)
		(layer "F.Cu")
		(net "M_B_CPU0_SB_DQ<28>")
	)
	(segment
		(start 291.556694 -197.741794)
		(end 289.48761 -197.741794)
		(width 0.1016)
		(layer "F.Cu")
		(net "M_B_CPU0_SB_DQ<28>")
	)
	(segment
		(start 294.904414 -198.166736)
		(end 293.799514 -198.166736)
		(width 0.20066)
		(layer "F.Cu")
		(net "M_B_CPU0_SB_DQ<28>")
	)
	(segment
		(start 333.078582 -223.085914)
		(end 333.069692 -223.080834)
		(width 0.088646)
		(layer "In4.Cu")
		(net "M_B_CPU0_SB_DQ<28>")
	)
	(segment
		(start 333.735934 -223.575626)
		(end 333.57947 -223.846644)
		(width 0.088646)
		(layer "In4.Cu")
		(net "M_B_CPU0_SB_DQ<28>")
	)
	(segment
		(start 331.71003 -222.322644)
		(end 331.108558 -221.721172)
		(width 0.088646)
		(layer "In4.Cu")
		(net "M_B_CPU0_SB_DQ<28>")
	)
	(segment
		(start 331.108558 -221.721172)
		(end 331.108558 -221.47657)
		(width 0.088646)
		(layer "In4.Cu")
		(net "M_B_CPU0_SB_DQ<28>")
	)
	(segment
		(start 312.707782 -196.73062)
		(end 312.546746 -196.891656)
		(width 0.18288)
		(layer "In4.Cu")
		(net "M_B_CPU0_SB_DQ<28>")
	)
	(segment
		(start 297.982894 -196.891656)
		(end 295.248584 -198.024242)
		(width 0.18288)
		(layer "In4.Cu")
		(net "M_B_CPU0_SB_DQ<28>")
	)
	(segment
		(start 320.085466 -203.934822)
		(end 316.029594 -199.87895)
		(width 0.18288)
		(layer "In4.Cu")
		(net "M_B_CPU0_SB_DQ<28>")
	)
	(segment
		(start 313.577224 -196.73062)
		(end 312.707782 -196.73062)
		(width 0.18288)
		(layer "In4.Cu")
		(net "M_B_CPU0_SB_DQ<28>")
	)
	(segment
		(start 332.058264 -222.263462)
		(end 332.043532 -222.272098)
		(width 0.088646)
		(layer "In4.Cu")
		(net "M_B_CPU0_SB_DQ<28>")
	)
	(segment
		(start 333.361284 -223.575626)
		(end 333.361284 -223.561402)
		(width 0.088646)
		(layer "In4.Cu")
		(net "M_B_CPU0_SB_DQ<28>")
	)
	(segment
		(start 332.89113 -222.761556)
		(end 332.89113 -222.746062)
		(width 0.088646)
		(layer "In4.Cu")
		(net "M_B_CPU0_SB_DQ<28>")
	)
	(segment
		(start 315.537596 -198.690992)
		(end 313.577224 -196.73062)
		(width 0.18288)
		(layer "In4.Cu")
		(net "M_B_CPU0_SB_DQ<28>")
	)
	(segment
		(start 329.370182 -221.268544)
		(end 325.777098 -217.67546)
		(width 0.18288)
		(layer "In4.Cu")
		(net "M_B_CPU0_SB_DQ<28>")
	)
	(segment
		(start 331.108558 -221.47657)
		(end 330.900532 -221.268544)
		(width 0.088646)
		(layer "In4.Cu")
		(net "M_B_CPU0_SB_DQ<28>")
	)
	(segment
		(start 331.856334 -222.322644)
		(end 331.71003 -222.322644)
		(width 0.088646)
		(layer "In4.Cu")
		(net "M_B_CPU0_SB_DQ<28>")
	)
	(segment
		(start 325.777098 -217.67546)
		(end 320.085466 -203.934822)
		(width 0.18288)
		(layer "In4.Cu")
		(net "M_B_CPU0_SB_DQ<28>")
	)
	(segment
		(start 295.248584 -198.024242)
		(end 294.904414 -198.166736)
		(width 0.18288)
		(layer "In4.Cu")
		(net "M_B_CPU0_SB_DQ<28>")
	)
	(segment
		(start 330.648564 -221.268544)
		(end 329.370182 -221.268544)
		(width 0.18288)
		(layer "In4.Cu")
		(net "M_B_CPU0_SB_DQ<28>")
	)
	(segment
		(start 330.900532 -221.268544)
		(end 330.648564 -221.268544)
		(width 0.088646)
		(layer "In4.Cu")
		(net "M_B_CPU0_SB_DQ<28>")
	)
	(segment
		(start 316.029594 -199.87895)
		(end 315.537596 -198.690992)
		(width 0.18288)
		(layer "In4.Cu")
		(net "M_B_CPU0_SB_DQ<28>")
	)
	(segment
		(start 333.57947 -223.846644)
		(end 333.501238 -223.867472)
		(width 0.088646)
		(layer "In4.Cu")
		(net "M_B_CPU0_SB_DQ<28>")
	)
	(segment
		(start 312.546746 -196.891656)
		(end 297.982894 -196.891656)
		(width 0.18288)
		(layer "In4.Cu")
		(net "M_B_CPU0_SB_DQ<28>")
	)
	(arc
		(start 333.069692 -223.080834)
		(mid 332.938778 -222.944474)
		(end 332.89113 -222.761556)
		(width 0.088646)
		(layer "In4.Cu")
		(net "M_B_CPU0_SB_DQ<28>")
	)
	(arc
		(start 333.361284 -223.561402)
		(mid 333.282065 -223.286717)
		(end 333.078582 -223.085914)
		(width 0.088646)
		(layer "In4.Cu")
		(net "M_B_CPU0_SB_DQ<28>")
	)
	(arc
		(start 332.043532 -222.272098)
		(mid 331.95326 -222.309697)
		(end 331.856334 -222.322644)
		(width 0.088646)
		(layer "In4.Cu")
		(net "M_B_CPU0_SB_DQ<28>")
	)
	(arc
		(start 333.501238 -223.867472)
		(mid 333.398093 -223.737447)
		(end 333.361284 -223.575626)
		(width 0.088646)
		(layer "In4.Cu")
		(net "M_B_CPU0_SB_DQ<28>")
	)
	(arc
		(start 332.608936 -222.272098)
		(mid 332.334737 -222.196263)
		(end 332.058264 -222.263462)
		(width 0.088646)
		(layer "In4.Cu")
		(net "M_B_CPU0_SB_DQ<28>")
	)
	(arc
		(start 332.89113 -222.746062)
		(mid 332.81176 -222.472328)
		(end 332.608936 -222.272098)
		(width 0.088646)
		(layer "In4.Cu")
		(net "M_B_CPU0_SB_DQ<28>")
	)
	(segment
		(start 299.004482 -201.56678)
		(end 297.899582 -201.56678)
		(width 0.20066)
		(layer "F.Cu")
		(net "M_B_CPU0_SB_DQ<27>")
	)
	(segment
		(start 297.08348 -201.56678)
		(end 296.875962 -201.774298)
		(width 0.20066)
		(layer "F.Cu")
		(net "M_B_CPU0_SB_DQ<27>")
	)
	(segment
		(start 292.178994 -201.692764)
		(end 292.05301 -201.56678)
		(width 0.20066)
		(layer "F.Cu")
		(net "M_B_CPU0_SB_DQ<27>")
	)
	(segment
		(start 295.000426 -201.991722)
		(end 292.927532 -201.991722)
		(width 0.1016)
		(layer "F.Cu")
		(net "M_B_CPU0_SB_DQ<27>")
	)
	(segment
		(start 295.693846 -201.690986)
		(end 295.693846 -201.842624)
		(width 0.20066)
		(layer "F.Cu")
		(net "M_B_CPU0_SB_DQ<27>")
	)
	(segment
		(start 292.689534 -201.991722)
		(end 292.67531 -202.005946)
		(width 0.101854)
		(layer "F.Cu")
		(net "M_B_CPU0_SB_DQ<27>")
	)
	(segment
		(start 292.321488 -202.005946)
		(end 292.178994 -201.863452)
		(width 0.20066)
		(layer "F.Cu")
		(net "M_B_CPU0_SB_DQ<27>")
	)
	(segment
		(start 292.927532 -201.991722)
		(end 292.689534 -201.991722)
		(width 0.101854)
		(layer "F.Cu")
		(net "M_B_CPU0_SB_DQ<27>")
	)
	(segment
		(start 297.899582 -201.56678)
		(end 297.08348 -201.56678)
		(width 0.20066)
		(layer "F.Cu")
		(net "M_B_CPU0_SB_DQ<27>")
	)
	(segment
		(start 296.42943 -201.774298)
		(end 296.217594 -201.562462)
		(width 0.20066)
		(layer "F.Cu")
		(net "M_B_CPU0_SB_DQ<27>")
	)
	(segment
		(start 292.178994 -201.863452)
		(end 292.178994 -201.692764)
		(width 0.20066)
		(layer "F.Cu")
		(net "M_B_CPU0_SB_DQ<27>")
	)
	(segment
		(start 335.14538 -226.553268)
		(end 335.14538 -226.017328)
		(width 0.20066)
		(layer "F.Cu")
		(net "M_B_CPU0_SB_DQ<27>")
	)
	(segment
		(start 296.217594 -201.562462)
		(end 295.82237 -201.562462)
		(width 0.20066)
		(layer "F.Cu")
		(net "M_B_CPU0_SB_DQ<27>")
	)
	(segment
		(start 292.05301 -201.56678)
		(end 290.355782 -201.56678)
		(width 0.20066)
		(layer "F.Cu")
		(net "M_B_CPU0_SB_DQ<27>")
	)
	(segment
		(start 295.544748 -201.991722)
		(end 295.000426 -201.991722)
		(width 0.20066)
		(layer "F.Cu")
		(net "M_B_CPU0_SB_DQ<27>")
	)
	(segment
		(start 296.875962 -201.774298)
		(end 296.42943 -201.774298)
		(width 0.20066)
		(layer "F.Cu")
		(net "M_B_CPU0_SB_DQ<27>")
	)
	(segment
		(start 292.67531 -202.005946)
		(end 292.321488 -202.005946)
		(width 0.20066)
		(layer "F.Cu")
		(net "M_B_CPU0_SB_DQ<27>")
	)
	(segment
		(start 295.693846 -201.842624)
		(end 295.544748 -201.991722)
		(width 0.20066)
		(layer "F.Cu")
		(net "M_B_CPU0_SB_DQ<27>")
	)
	(segment
		(start 295.82237 -201.562462)
		(end 295.693846 -201.690986)
		(width 0.20066)
		(layer "F.Cu")
		(net "M_B_CPU0_SB_DQ<27>")
	)
	(segment
		(start 332.492858 -225.81108)
		(end 332.007464 -225.325686)
		(width 0.088646)
		(layer "In4.Cu")
		(net "M_B_CPU0_SB_DQ<27>")
	)
	(segment
		(start 303.032414 -201.876406)
		(end 302.872394 -202.036426)
		(width 0.18288)
		(layer "In4.Cu")
		(net "M_B_CPU0_SB_DQ<27>")
	)
	(segment
		(start 314.946538 -202.919076)
		(end 313.371484 -202.919076)
		(width 0.18288)
		(layer "In4.Cu")
		(net "M_B_CPU0_SB_DQ<27>")
	)
	(segment
		(start 311.503568 -201.309732)
		(end 311.503568 -201.05116)
		(width 0.18288)
		(layer "In4.Cu")
		(net "M_B_CPU0_SB_DQ<27>")
	)
	(segment
		(start 300.999906 -201.853546)
		(end 300.817026 -202.036426)
		(width 0.18288)
		(layer "In4.Cu")
		(net "M_B_CPU0_SB_DQ<27>")
	)
	(segment
		(start 309.027322 -201.577956)
		(end 308.702202 -201.577956)
		(width 0.18288)
		(layer "In4.Cu")
		(net "M_B_CPU0_SB_DQ<27>")
	)
	(segment
		(start 307.325776 -200.634854)
		(end 306.686204 -201.274426)
		(width 0.18288)
		(layer "In4.Cu")
		(net "M_B_CPU0_SB_DQ<27>")
	)
	(segment
		(start 302.872394 -202.036426)
		(end 301.873666 -202.036426)
		(width 0.18288)
		(layer "In4.Cu")
		(net "M_B_CPU0_SB_DQ<27>")
	)
	(segment
		(start 330.79182 -223.897952)
		(end 330.648564 -223.897952)
		(width 0.088646)
		(layer "In4.Cu")
		(net "M_B_CPU0_SB_DQ<27>")
	)
	(segment
		(start 330.648564 -223.897952)
		(end 328.11085 -223.897952)
		(width 0.18288)
		(layer "In4.Cu")
		(net "M_B_CPU0_SB_DQ<27>")
	)
	(segment
		(start 328.11085 -223.897952)
		(end 323.356732 -219.143834)
		(width 0.18288)
		(layer "In4.Cu")
		(net "M_B_CPU0_SB_DQ<27>")
	)
	(segment
		(start 311.3913 -201.680572)
		(end 311.3913 -201.422)
		(width 0.18288)
		(layer "In4.Cu")
		(net "M_B_CPU0_SB_DQ<27>")
	)
	(segment
		(start 304.85207 -200.847452)
		(end 304.85207 -201.284078)
		(width 0.18288)
		(layer "In4.Cu")
		(net "M_B_CPU0_SB_DQ<27>")
	)
	(segment
		(start 300.999906 -201.621898)
		(end 300.999906 -201.853546)
		(width 0.18288)
		(layer "In4.Cu")
		(net "M_B_CPU0_SB_DQ<27>")
	)
	(segment
		(start 301.507906 -201.439018)
		(end 301.182786 -201.439018)
		(width 0.18288)
		(layer "In4.Cu")
		(net "M_B_CPU0_SB_DQ<27>")
	)
	(segment
		(start 312.250836 -201.798428)
		(end 311.992264 -201.798428)
		(width 0.18288)
		(layer "In4.Cu")
		(net "M_B_CPU0_SB_DQ<27>")
	)
	(segment
		(start 323.356732 -219.143834)
		(end 317.830454 -205.802992)
		(width 0.18288)
		(layer "In4.Cu")
		(net "M_B_CPU0_SB_DQ<27>")
	)
	(segment
		(start 308.519322 -200.817734)
		(end 308.336442 -200.634854)
		(width 0.18288)
		(layer "In4.Cu")
		(net "M_B_CPU0_SB_DQ<27>")
	)
	(segment
		(start 309.393082 -200.634854)
		(end 309.210202 -200.817734)
		(width 0.18288)
		(layer "In4.Cu")
		(net "M_B_CPU0_SB_DQ<27>")
	)
	(segment
		(start 332.007464 -225.325686)
		(end 332.007464 -225.113596)
		(width 0.088646)
		(layer "In4.Cu")
		(net "M_B_CPU0_SB_DQ<27>")
	)
	(segment
		(start 309.210202 -200.817734)
		(end 309.210202 -201.395076)
		(width 0.18288)
		(layer "In4.Cu")
		(net "M_B_CPU0_SB_DQ<27>")
	)
	(segment
		(start 301.690786 -201.621898)
		(end 301.507906 -201.439018)
		(width 0.18288)
		(layer "In4.Cu")
		(net "M_B_CPU0_SB_DQ<27>")
	)
	(segment
		(start 333.078836 -225.69297)
		(end 332.87462 -225.81108)
		(width 0.088646)
		(layer "In4.Cu")
		(net "M_B_CPU0_SB_DQ<27>")
	)
	(segment
		(start 317.830454 -205.802992)
		(end 314.946538 -202.919076)
		(width 0.18288)
		(layer "In4.Cu")
		(net "M_B_CPU0_SB_DQ<27>")
	)
	(segment
		(start 300.817026 -202.036426)
		(end 299.474128 -202.036426)
		(width 0.18288)
		(layer "In4.Cu")
		(net "M_B_CPU0_SB_DQ<27>")
	)
	(segment
		(start 301.182786 -201.439018)
		(end 300.999906 -201.621898)
		(width 0.18288)
		(layer "In4.Cu")
		(net "M_B_CPU0_SB_DQ<27>")
	)
	(segment
		(start 305.781964 -200.687432)
		(end 305.01209 -200.687432)
		(width 0.18288)
		(layer "In4.Cu")
		(net "M_B_CPU0_SB_DQ<27>")
	)
	(segment
		(start 304.69205 -201.444098)
		(end 303.192434 -201.444098)
		(width 0.18288)
		(layer "In4.Cu")
		(net "M_B_CPU0_SB_DQ<27>")
	)
	(segment
		(start 306.368958 -201.274426)
		(end 305.781964 -200.687432)
		(width 0.18288)
		(layer "In4.Cu")
		(net "M_B_CPU0_SB_DQ<27>")
	)
	(segment
		(start 311.503568 -201.05116)
		(end 311.087262 -200.634854)
		(width 0.18288)
		(layer "In4.Cu")
		(net "M_B_CPU0_SB_DQ<27>")
	)
	(segment
		(start 332.87462 -225.81108)
		(end 332.492858 -225.81108)
		(width 0.088646)
		(layer "In4.Cu")
		(net "M_B_CPU0_SB_DQ<27>")
	)
	(segment
		(start 308.336442 -200.634854)
		(end 307.325776 -200.634854)
		(width 0.18288)
		(layer "In4.Cu")
		(net "M_B_CPU0_SB_DQ<27>")
	)
	(segment
		(start 301.873666 -202.036426)
		(end 301.690786 -201.853546)
		(width 0.18288)
		(layer "In4.Cu")
		(net "M_B_CPU0_SB_DQ<27>")
	)
	(segment
		(start 309.210202 -201.395076)
		(end 309.027322 -201.577956)
		(width 0.18288)
		(layer "In4.Cu")
		(net "M_B_CPU0_SB_DQ<27>")
	)
	(segment
		(start 303.032414 -201.604118)
		(end 303.032414 -201.876406)
		(width 0.18288)
		(layer "In4.Cu")
		(net "M_B_CPU0_SB_DQ<27>")
	)
	(segment
		(start 332.007464 -225.113596)
		(end 330.79182 -223.897952)
		(width 0.088646)
		(layer "In4.Cu")
		(net "M_B_CPU0_SB_DQ<27>")
	)
	(segment
		(start 311.087262 -200.634854)
		(end 309.393082 -200.634854)
		(width 0.18288)
		(layer "In4.Cu")
		(net "M_B_CPU0_SB_DQ<27>")
	)
	(segment
		(start 308.519322 -201.395076)
		(end 308.519322 -200.817734)
		(width 0.18288)
		(layer "In4.Cu")
		(net "M_B_CPU0_SB_DQ<27>")
	)
	(segment
		(start 303.192434 -201.444098)
		(end 303.032414 -201.604118)
		(width 0.18288)
		(layer "In4.Cu")
		(net "M_B_CPU0_SB_DQ<27>")
	)
	(segment
		(start 311.621424 -201.910696)
		(end 311.3913 -201.680572)
		(width 0.18288)
		(layer "In4.Cu")
		(net "M_B_CPU0_SB_DQ<27>")
	)
	(segment
		(start 313.371484 -202.919076)
		(end 312.250836 -201.798428)
		(width 0.18288)
		(layer "In4.Cu")
		(net "M_B_CPU0_SB_DQ<27>")
	)
	(segment
		(start 301.690786 -201.853546)
		(end 301.690786 -201.621898)
		(width 0.18288)
		(layer "In4.Cu")
		(net "M_B_CPU0_SB_DQ<27>")
	)
	(segment
		(start 304.85207 -201.284078)
		(end 304.69205 -201.444098)
		(width 0.18288)
		(layer "In4.Cu")
		(net "M_B_CPU0_SB_DQ<27>")
	)
	(segment
		(start 306.686204 -201.274426)
		(end 306.368958 -201.274426)
		(width 0.18288)
		(layer "In4.Cu")
		(net "M_B_CPU0_SB_DQ<27>")
	)
	(segment
		(start 334.791558 -225.922586)
		(end 334.38719 -225.689414)
		(width 0.088646)
		(layer "In4.Cu")
		(net "M_B_CPU0_SB_DQ<27>")
	)
	(segment
		(start 308.702202 -201.577956)
		(end 308.519322 -201.395076)
		(width 0.18288)
		(layer "In4.Cu")
		(net "M_B_CPU0_SB_DQ<27>")
	)
	(segment
		(start 311.992264 -201.798428)
		(end 311.879996 -201.910696)
		(width 0.18288)
		(layer "In4.Cu")
		(net "M_B_CPU0_SB_DQ<27>")
	)
	(segment
		(start 311.879996 -201.910696)
		(end 311.621424 -201.910696)
		(width 0.18288)
		(layer "In4.Cu")
		(net "M_B_CPU0_SB_DQ<27>")
	)
	(segment
		(start 305.01209 -200.687432)
		(end 304.85207 -200.847452)
		(width 0.18288)
		(layer "In4.Cu")
		(net "M_B_CPU0_SB_DQ<27>")
	)
	(segment
		(start 299.474128 -202.036426)
		(end 299.004482 -201.56678)
		(width 0.18288)
		(layer "In4.Cu")
		(net "M_B_CPU0_SB_DQ<27>")
	)
	(segment
		(start 311.3913 -201.422)
		(end 311.503568 -201.309732)
		(width 0.18288)
		(layer "In4.Cu")
		(net "M_B_CPU0_SB_DQ<27>")
	)
	(arc
		(start 334.38719 -225.689414)
		(mid 334.202335 -225.642496)
		(end 334.018382 -225.692716)
		(width 0.088646)
		(layer "In4.Cu")
		(net "M_B_CPU0_SB_DQ<27>")
	)
	(arc
		(start 334.018382 -225.692716)
		(mid 333.735963 -225.768526)
		(end 333.453486 -225.69297)
		(width 0.088646)
		(layer "In4.Cu")
		(net "M_B_CPU0_SB_DQ<27>")
	)
	(arc
		(start 333.453486 -225.69297)
		(mid 333.266178 -225.642861)
		(end 333.078836 -225.69297)
		(width 0.088646)
		(layer "In4.Cu")
		(net "M_B_CPU0_SB_DQ<27>")
	)
	(arc
		(start 335.14538 -226.017328)
		(mid 334.962263 -225.993152)
		(end 334.791558 -225.922586)
		(width 0.088646)
		(layer "In4.Cu")
		(net "M_B_CPU0_SB_DQ<27>")
	)
	(segment
		(start 297.899582 -203.266802)
		(end 296.584878 -203.266802)
		(width 0.20066)
		(layer "F.Cu")
		(net "M_B_CPU0_SB_DQ<26>")
	)
	(segment
		(start 296.584878 -203.266802)
		(end 296.373042 -203.478638)
		(width 0.20066)
		(layer "F.Cu")
		(net "M_B_CPU0_SB_DQ<26>")
	)
	(segment
		(start 295.000426 -202.84186)
		(end 292.940486 -202.84186)
		(width 0.1016)
		(layer "F.Cu")
		(net "M_B_CPU0_SB_DQ<26>")
	)
	(segment
		(start 292.940486 -202.84186)
		(end 292.68547 -202.84186)
		(width 0.101854)
		(layer "F.Cu")
		(net "M_B_CPU0_SB_DQ<26>")
	)
	(segment
		(start 295.944544 -203.478638)
		(end 295.777158 -203.311252)
		(width 0.20066)
		(layer "F.Cu")
		(net "M_B_CPU0_SB_DQ<26>")
	)
	(segment
		(start 295.777158 -203.311252)
		(end 295.777158 -202.985624)
		(width 0.20066)
		(layer "F.Cu")
		(net "M_B_CPU0_SB_DQ<26>")
	)
	(segment
		(start 334.675734 -226.831398)
		(end 334.67548 -226.831144)
		(width 0.20066)
		(layer "F.Cu")
		(net "M_B_CPU0_SB_DQ<26>")
	)
	(segment
		(start 299.004482 -203.266802)
		(end 297.899582 -203.266802)
		(width 0.20066)
		(layer "F.Cu")
		(net "M_B_CPU0_SB_DQ<26>")
	)
	(segment
		(start 291.937948 -202.8317)
		(end 291.502846 -203.266802)
		(width 0.20066)
		(layer "F.Cu")
		(net "M_B_CPU0_SB_DQ<26>")
	)
	(segment
		(start 292.68547 -202.84186)
		(end 292.67531 -202.8317)
		(width 0.101854)
		(layer "F.Cu")
		(net "M_B_CPU0_SB_DQ<26>")
	)
	(segment
		(start 296.373042 -203.478638)
		(end 295.944544 -203.478638)
		(width 0.20066)
		(layer "F.Cu")
		(net "M_B_CPU0_SB_DQ<26>")
	)
	(segment
		(start 334.675734 -227.367084)
		(end 334.675734 -226.831398)
		(width 0.20066)
		(layer "F.Cu")
		(net "M_B_CPU0_SB_DQ<26>")
	)
	(segment
		(start 291.502846 -203.266802)
		(end 290.355782 -203.266802)
		(width 0.20066)
		(layer "F.Cu")
		(net "M_B_CPU0_SB_DQ<26>")
	)
	(segment
		(start 292.67531 -202.8317)
		(end 291.937948 -202.8317)
		(width 0.20066)
		(layer "F.Cu")
		(net "M_B_CPU0_SB_DQ<26>")
	)
	(segment
		(start 295.633394 -202.84186)
		(end 295.000426 -202.84186)
		(width 0.20066)
		(layer "F.Cu")
		(net "M_B_CPU0_SB_DQ<26>")
	)
	(segment
		(start 295.777158 -202.985624)
		(end 295.633394 -202.84186)
		(width 0.20066)
		(layer "F.Cu")
		(net "M_B_CPU0_SB_DQ<26>")
	)
	(segment
		(start 306.32273 -202.975464)
		(end 306.13985 -202.792584)
		(width 0.18288)
		(layer "In4.Cu")
		(net "M_B_CPU0_SB_DQ<26>")
	)
	(segment
		(start 327.527158 -224.893632)
		(end 322.632578 -219.999052)
		(width 0.18288)
		(layer "In4.Cu")
		(net "M_B_CPU0_SB_DQ<26>")
	)
	(segment
		(start 307.166518 -202.872086)
		(end 307.166518 -203.121006)
		(width 0.18288)
		(layer "In4.Cu")
		(net "M_B_CPU0_SB_DQ<26>")
	)
	(segment
		(start 306.13985 -202.792584)
		(end 305.81473 -202.792584)
		(width 0.18288)
		(layer "In4.Cu")
		(net "M_B_CPU0_SB_DQ<26>")
	)
	(segment
		(start 310.388 -202.712066)
		(end 309.53837 -202.712066)
		(width 0.18288)
		(layer "In4.Cu")
		(net "M_B_CPU0_SB_DQ<26>")
	)
	(segment
		(start 317.19647 -206.875126)
		(end 314.94857 -204.627226)
		(width 0.18288)
		(layer "In4.Cu")
		(net "M_B_CPU0_SB_DQ<26>")
	)
	(segment
		(start 309.35549 -202.894946)
		(end 309.35549 -203.708508)
		(width 0.18288)
		(layer "In4.Cu")
		(net "M_B_CPU0_SB_DQ<26>")
	)
	(segment
		(start 309.53837 -202.712066)
		(end 309.35549 -202.894946)
		(width 0.18288)
		(layer "In4.Cu")
		(net "M_B_CPU0_SB_DQ<26>")
	)
	(segment
		(start 307.166518 -203.121006)
		(end 306.83454 -203.452984)
		(width 0.18288)
		(layer "In4.Cu")
		(net "M_B_CPU0_SB_DQ<26>")
	)
	(segment
		(start 332.310994 -226.331272)
		(end 330.873354 -224.893632)
		(width 0.088646)
		(layer "In4.Cu")
		(net "M_B_CPU0_SB_DQ<26>")
	)
	(segment
		(start 307.326538 -202.712066)
		(end 307.166518 -202.872086)
		(width 0.18288)
		(layer "In4.Cu")
		(net "M_B_CPU0_SB_DQ<26>")
	)
	(segment
		(start 305.12385 -204.113384)
		(end 304.94097 -203.930504)
		(width 0.18288)
		(layer "In4.Cu")
		(net "M_B_CPU0_SB_DQ<26>")
	)
	(segment
		(start 302.714406 -203.798932)
		(end 301.734728 -203.798932)
		(width 0.18288)
		(layer "In4.Cu")
		(net "M_B_CPU0_SB_DQ<26>")
	)
	(segment
		(start 330.873354 -224.893632)
		(end 330.648564 -224.893632)
		(width 0.088646)
		(layer "In4.Cu")
		(net "M_B_CPU0_SB_DQ<26>")
	)
	(segment
		(start 300.098206 -203.798932)
		(end 299.566076 -203.266802)
		(width 0.18288)
		(layer "In4.Cu")
		(net "M_B_CPU0_SB_DQ<26>")
	)
	(segment
		(start 305.63185 -203.930504)
		(end 305.44897 -204.113384)
		(width 0.18288)
		(layer "In4.Cu")
		(net "M_B_CPU0_SB_DQ<26>")
	)
	(segment
		(start 305.63185 -202.975464)
		(end 305.63185 -203.930504)
		(width 0.18288)
		(layer "In4.Cu")
		(net "M_B_CPU0_SB_DQ<26>")
	)
	(segment
		(start 308.84749 -203.891388)
		(end 308.66461 -203.708508)
		(width 0.18288)
		(layer "In4.Cu")
		(net "M_B_CPU0_SB_DQ<26>")
	)
	(segment
		(start 313.108594 -204.627226)
		(end 312.101738 -203.62037)
		(width 0.18288)
		(layer "In4.Cu")
		(net "M_B_CPU0_SB_DQ<26>")
	)
	(segment
		(start 334.018636 -226.341686)
		(end 334.008222 -226.33559)
		(width 0.088646)
		(layer "In4.Cu")
		(net "M_B_CPU0_SB_DQ<26>")
	)
	(segment
		(start 310.645048 -203.40828)
		(end 310.645048 -202.969114)
		(width 0.18288)
		(layer "In4.Cu")
		(net "M_B_CPU0_SB_DQ<26>")
	)
	(segment
		(start 301.368968 -203.175616)
		(end 301.043848 -203.175616)
		(width 0.18288)
		(layer "In4.Cu")
		(net "M_B_CPU0_SB_DQ<26>")
	)
	(segment
		(start 300.678088 -203.798932)
		(end 300.098206 -203.798932)
		(width 0.18288)
		(layer "In4.Cu")
		(net "M_B_CPU0_SB_DQ<26>")
	)
	(segment
		(start 301.043848 -203.175616)
		(end 300.860968 -203.358496)
		(width 0.18288)
		(layer "In4.Cu")
		(net "M_B_CPU0_SB_DQ<26>")
	)
	(segment
		(start 334.67548 -226.831144)
		(end 334.362806 -226.831144)
		(width 0.088646)
		(layer "In4.Cu")
		(net "M_B_CPU0_SB_DQ<26>")
	)
	(segment
		(start 314.94857 -204.627226)
		(end 313.108594 -204.627226)
		(width 0.18288)
		(layer "In4.Cu")
		(net "M_B_CPU0_SB_DQ<26>")
	)
	(segment
		(start 301.734728 -203.798932)
		(end 301.551848 -203.616052)
		(width 0.18288)
		(layer "In4.Cu")
		(net "M_B_CPU0_SB_DQ<26>")
	)
	(segment
		(start 330.648564 -224.893632)
		(end 327.527158 -224.893632)
		(width 0.18288)
		(layer "In4.Cu")
		(net "M_B_CPU0_SB_DQ<26>")
	)
	(segment
		(start 304.94097 -203.930504)
		(end 304.94097 -203.635864)
		(width 0.18288)
		(layer "In4.Cu")
		(net "M_B_CPU0_SB_DQ<26>")
	)
	(segment
		(start 312.101738 -203.62037)
		(end 310.857138 -203.62037)
		(width 0.18288)
		(layer "In4.Cu")
		(net "M_B_CPU0_SB_DQ<26>")
	)
	(segment
		(start 304.94097 -203.635864)
		(end 304.75809 -203.452984)
		(width 0.18288)
		(layer "In4.Cu")
		(net "M_B_CPU0_SB_DQ<26>")
	)
	(segment
		(start 300.860968 -203.358496)
		(end 300.860968 -203.616052)
		(width 0.18288)
		(layer "In4.Cu")
		(net "M_B_CPU0_SB_DQ<26>")
	)
	(segment
		(start 334.362806 -226.831144)
		(end 334.297528 -226.765866)
		(width 0.088646)
		(layer "In4.Cu")
		(net "M_B_CPU0_SB_DQ<26>")
	)
	(segment
		(start 300.860968 -203.616052)
		(end 300.678088 -203.798932)
		(width 0.18288)
		(layer "In4.Cu")
		(net "M_B_CPU0_SB_DQ<26>")
	)
	(segment
		(start 303.060354 -203.452984)
		(end 302.714406 -203.798932)
		(width 0.18288)
		(layer "In4.Cu")
		(net "M_B_CPU0_SB_DQ<26>")
	)
	(segment
		(start 310.645048 -202.969114)
		(end 310.388 -202.712066)
		(width 0.18288)
		(layer "In4.Cu")
		(net "M_B_CPU0_SB_DQ<26>")
	)
	(segment
		(start 309.35549 -203.708508)
		(end 309.17261 -203.891388)
		(width 0.18288)
		(layer "In4.Cu")
		(net "M_B_CPU0_SB_DQ<26>")
	)
	(segment
		(start 301.551848 -203.616052)
		(end 301.551848 -203.358496)
		(width 0.18288)
		(layer "In4.Cu")
		(net "M_B_CPU0_SB_DQ<26>")
	)
	(segment
		(start 306.32273 -203.270104)
		(end 306.32273 -202.975464)
		(width 0.18288)
		(layer "In4.Cu")
		(net "M_B_CPU0_SB_DQ<26>")
	)
	(segment
		(start 308.66461 -203.708508)
		(end 308.66461 -202.894946)
		(width 0.18288)
		(layer "In4.Cu")
		(net "M_B_CPU0_SB_DQ<26>")
	)
	(segment
		(start 305.44897 -204.113384)
		(end 305.12385 -204.113384)
		(width 0.18288)
		(layer "In4.Cu")
		(net "M_B_CPU0_SB_DQ<26>")
	)
	(segment
		(start 301.551848 -203.358496)
		(end 301.368968 -203.175616)
		(width 0.18288)
		(layer "In4.Cu")
		(net "M_B_CPU0_SB_DQ<26>")
	)
	(segment
		(start 308.48173 -202.712066)
		(end 307.326538 -202.712066)
		(width 0.18288)
		(layer "In4.Cu")
		(net "M_B_CPU0_SB_DQ<26>")
	)
	(segment
		(start 299.566076 -203.266802)
		(end 299.004482 -203.266802)
		(width 0.18288)
		(layer "In4.Cu")
		(net "M_B_CPU0_SB_DQ<26>")
	)
	(segment
		(start 332.471268 -226.331272)
		(end 332.310994 -226.331272)
		(width 0.088646)
		(layer "In4.Cu")
		(net "M_B_CPU0_SB_DQ<26>")
	)
	(segment
		(start 306.83454 -203.452984)
		(end 306.50561 -203.452984)
		(width 0.18288)
		(layer "In4.Cu")
		(net "M_B_CPU0_SB_DQ<26>")
	)
	(segment
		(start 322.632578 -219.999052)
		(end 317.19647 -206.875126)
		(width 0.18288)
		(layer "In4.Cu")
		(net "M_B_CPU0_SB_DQ<26>")
	)
	(segment
		(start 305.81473 -202.792584)
		(end 305.63185 -202.975464)
		(width 0.18288)
		(layer "In4.Cu")
		(net "M_B_CPU0_SB_DQ<26>")
	)
	(segment
		(start 308.66461 -202.894946)
		(end 308.48173 -202.712066)
		(width 0.18288)
		(layer "In4.Cu")
		(net "M_B_CPU0_SB_DQ<26>")
	)
	(segment
		(start 310.857138 -203.62037)
		(end 310.645048 -203.40828)
		(width 0.18288)
		(layer "In4.Cu")
		(net "M_B_CPU0_SB_DQ<26>")
	)
	(segment
		(start 306.50561 -203.452984)
		(end 306.32273 -203.270104)
		(width 0.18288)
		(layer "In4.Cu")
		(net "M_B_CPU0_SB_DQ<26>")
	)
	(segment
		(start 304.75809 -203.452984)
		(end 303.060354 -203.452984)
		(width 0.18288)
		(layer "In4.Cu")
		(net "M_B_CPU0_SB_DQ<26>")
	)
	(segment
		(start 309.17261 -203.891388)
		(end 308.84749 -203.891388)
		(width 0.18288)
		(layer "In4.Cu")
		(net "M_B_CPU0_SB_DQ<26>")
	)
	(arc
		(start 333.452978 -226.341686)
		(mid 333.26578 -226.391829)
		(end 333.078582 -226.341686)
		(width 0.088646)
		(layer "In4.Cu")
		(net "M_B_CPU0_SB_DQ<26>")
	)
	(arc
		(start 332.584298 -226.306888)
		(mid 332.571656 -226.311867)
		(end 332.558898 -226.31654)
		(width 0.088646)
		(layer "In4.Cu")
		(net "M_B_CPU0_SB_DQ<26>")
	)
	(arc
		(start 332.558898 -226.31654)
		(mid 332.515704 -226.327597)
		(end 332.471268 -226.331272)
		(width 0.088646)
		(layer "In4.Cu")
		(net "M_B_CPU0_SB_DQ<26>")
	)
	(arc
		(start 334.297528 -226.765866)
		(mid 334.208399 -226.520691)
		(end 334.018636 -226.341686)
		(width 0.088646)
		(layer "In4.Cu")
		(net "M_B_CPU0_SB_DQ<26>")
	)
	(arc
		(start 334.008222 -226.33559)
		(mid 333.72979 -226.265744)
		(end 333.452978 -226.341686)
		(width 0.088646)
		(layer "In4.Cu")
		(net "M_B_CPU0_SB_DQ<26>")
	)
	(arc
		(start 333.078582 -226.341686)
		(mid 332.835465 -226.267298)
		(end 332.584298 -226.306888)
		(width 0.088646)
		(layer "In4.Cu")
		(net "M_B_CPU0_SB_DQ<26>")
	)
	(segment
		(start 289.240468 -201.991722)
		(end 289.231578 -201.982832)
		(width 0.1016)
		(layer "F.Cu")
		(net "M_B_CPU0_SB_DQ<25>")
	)
	(segment
		(start 293.799514 -202.416664)
		(end 292.160198 -202.416664)
		(width 0.20066)
		(layer "F.Cu")
		(net "M_B_CPU0_SB_DQ<25>")
	)
	(segment
		(start 288.305748 -202.627992)
		(end 287.801304 -202.627992)
		(width 0.20066)
		(layer "F.Cu")
		(net "M_B_CPU0_SB_DQ<25>")
	)
	(segment
		(start 294.904414 -202.416664)
		(end 293.799514 -202.416664)
		(width 0.20066)
		(layer "F.Cu")
		(net "M_B_CPU0_SB_DQ<25>")
	)
	(segment
		(start 288.62274 -201.982832)
		(end 288.46018 -202.145392)
		(width 0.20066)
		(layer "F.Cu")
		(net "M_B_CPU0_SB_DQ<25>")
	)
	(segment
		(start 291.225986 -201.991722)
		(end 289.240468 -201.991722)
		(width 0.1016)
		(layer "F.Cu")
		(net "M_B_CPU0_SB_DQ<25>")
	)
	(segment
		(start 289.231578 -201.982832)
		(end 288.62274 -201.982832)
		(width 0.20066)
		(layer "F.Cu")
		(net "M_B_CPU0_SB_DQ<25>")
	)
	(segment
		(start 288.46018 -202.47356)
		(end 288.305748 -202.627992)
		(width 0.20066)
		(layer "F.Cu")
		(net "M_B_CPU0_SB_DQ<25>")
	)
	(segment
		(start 291.556694 -201.991722)
		(end 291.225986 -201.991722)
		(width 0.101854)
		(layer "F.Cu")
		(net "M_B_CPU0_SB_DQ<25>")
	)
	(segment
		(start 333.26578 -226.553268)
		(end 333.26578 -226.017328)
		(width 0.20066)
		(layer "F.Cu")
		(net "M_B_CPU0_SB_DQ<25>")
	)
	(segment
		(start 291.735256 -201.991722)
		(end 291.556694 -201.991722)
		(width 0.20066)
		(layer "F.Cu")
		(net "M_B_CPU0_SB_DQ<25>")
	)
	(segment
		(start 287.589976 -202.416664)
		(end 286.255714 -202.416664)
		(width 0.20066)
		(layer "F.Cu")
		(net "M_B_CPU0_SB_DQ<25>")
	)
	(segment
		(start 292.160198 -202.416664)
		(end 291.735256 -201.991722)
		(width 0.20066)
		(layer "F.Cu")
		(net "M_B_CPU0_SB_DQ<25>")
	)
	(segment
		(start 288.46018 -202.145392)
		(end 288.46018 -202.47356)
		(width 0.20066)
		(layer "F.Cu")
		(net "M_B_CPU0_SB_DQ<25>")
	)
	(segment
		(start 287.801304 -202.627992)
		(end 287.589976 -202.416664)
		(width 0.20066)
		(layer "F.Cu")
		(net "M_B_CPU0_SB_DQ<25>")
	)
	(segment
		(start 296.89425 -203.02474)
		(end 296.89425 -203.338684)
		(width 0.18288)
		(layer "In4.Cu")
		(net "M_B_CPU0_SB_DQ<25>")
	)
	(segment
		(start 298.45889 -202.84186)
		(end 298.27601 -203.02474)
		(width 0.18288)
		(layer "In4.Cu")
		(net "M_B_CPU0_SB_DQ<25>")
	)
	(segment
		(start 298.27601 -203.02474)
		(end 298.27601 -203.338684)
		(width 0.18288)
		(layer "In4.Cu")
		(net "M_B_CPU0_SB_DQ<25>")
	)
	(segment
		(start 310.993536 -202.098148)
		(end 307.47589 -202.098148)
		(width 0.18288)
		(layer "In4.Cu")
		(net "M_B_CPU0_SB_DQ<25>")
	)
	(segment
		(start 303.48047 -202.544426)
		(end 301.366174 -202.544426)
		(width 0.18288)
		(layer "In4.Cu")
		(net "M_B_CPU0_SB_DQ<25>")
	)
	(segment
		(start 311.20588 -202.310492)
		(end 310.993536 -202.098148)
		(width 0.18288)
		(layer "In4.Cu")
		(net "M_B_CPU0_SB_DQ<25>")
	)
	(segment
		(start 303.88687 -202.950826)
		(end 303.48047 -202.544426)
		(width 0.18288)
		(layer "In4.Cu")
		(net "M_B_CPU0_SB_DQ<25>")
	)
	(segment
		(start 311.442862 -203.00823)
		(end 311.20588 -202.771248)
		(width 0.18288)
		(layer "In4.Cu")
		(net "M_B_CPU0_SB_DQ<25>")
	)
	(segment
		(start 301.366174 -202.544426)
		(end 301.276004 -202.634596)
		(width 0.18288)
		(layer "In4.Cu")
		(net "M_B_CPU0_SB_DQ<25>")
	)
	(segment
		(start 296.89425 -203.338684)
		(end 296.71137 -203.521564)
		(width 0.18288)
		(layer "In4.Cu")
		(net "M_B_CPU0_SB_DQ<25>")
	)
	(segment
		(start 296.38625 -203.521564)
		(end 296.20337 -203.338684)
		(width 0.18288)
		(layer "In4.Cu")
		(net "M_B_CPU0_SB_DQ<25>")
	)
	(segment
		(start 307.47589 -202.098148)
		(end 307.289962 -201.91222)
		(width 0.18288)
		(layer "In4.Cu")
		(net "M_B_CPU0_SB_DQ<25>")
	)
	(segment
		(start 296.02049 -202.84186)
		(end 295.32961 -202.84186)
		(width 0.18288)
		(layer "In4.Cu")
		(net "M_B_CPU0_SB_DQ<25>")
	)
	(segment
		(start 331.666088 -225.133662)
		(end 330.928218 -224.395792)
		(width 0.088646)
		(layer "In4.Cu")
		(net "M_B_CPU0_SB_DQ<25>")
	)
	(segment
		(start 301.276004 -202.634596)
		(end 299.414692 -202.634596)
		(width 0.18288)
		(layer "In4.Cu")
		(net "M_B_CPU0_SB_DQ<25>")
	)
	(segment
		(start 305.209448 -202.186032)
		(end 304.444654 -202.950826)
		(width 0.18288)
		(layer "In4.Cu")
		(net "M_B_CPU0_SB_DQ<25>")
	)
	(segment
		(start 327.793604 -224.395792)
		(end 323.012308 -219.614496)
		(width 0.18288)
		(layer "In4.Cu")
		(net "M_B_CPU0_SB_DQ<25>")
	)
	(segment
		(start 332.351634 -226.017328)
		(end 331.666088 -225.331782)
		(width 0.088646)
		(layer "In4.Cu")
		(net "M_B_CPU0_SB_DQ<25>")
	)
	(segment
		(start 317.514986 -206.342742)
		(end 314.70727 -203.535026)
		(width 0.18288)
		(layer "In4.Cu")
		(net "M_B_CPU0_SB_DQ<25>")
	)
	(segment
		(start 295.32961 -202.84186)
		(end 294.904414 -202.416664)
		(width 0.18288)
		(layer "In4.Cu")
		(net "M_B_CPU0_SB_DQ<25>")
	)
	(segment
		(start 312.414158 -203.00823)
		(end 311.442862 -203.00823)
		(width 0.18288)
		(layer "In4.Cu")
		(net "M_B_CPU0_SB_DQ<25>")
	)
	(segment
		(start 296.20337 -203.338684)
		(end 296.20337 -203.02474)
		(width 0.18288)
		(layer "In4.Cu")
		(net "M_B_CPU0_SB_DQ<25>")
	)
	(segment
		(start 297.76801 -203.521564)
		(end 297.58513 -203.338684)
		(width 0.18288)
		(layer "In4.Cu")
		(net "M_B_CPU0_SB_DQ<25>")
	)
	(segment
		(start 297.58513 -203.338684)
		(end 297.58513 -203.02474)
		(width 0.18288)
		(layer "In4.Cu")
		(net "M_B_CPU0_SB_DQ<25>")
	)
	(segment
		(start 314.70727 -203.535026)
		(end 312.940954 -203.535026)
		(width 0.18288)
		(layer "In4.Cu")
		(net "M_B_CPU0_SB_DQ<25>")
	)
	(segment
		(start 299.207428 -202.84186)
		(end 298.45889 -202.84186)
		(width 0.18288)
		(layer "In4.Cu")
		(net "M_B_CPU0_SB_DQ<25>")
	)
	(segment
		(start 299.414692 -202.634596)
		(end 299.207428 -202.84186)
		(width 0.18288)
		(layer "In4.Cu")
		(net "M_B_CPU0_SB_DQ<25>")
	)
	(segment
		(start 323.012308 -219.614496)
		(end 317.514986 -206.342742)
		(width 0.18288)
		(layer "In4.Cu")
		(net "M_B_CPU0_SB_DQ<25>")
	)
	(segment
		(start 297.40225 -202.84186)
		(end 297.07713 -202.84186)
		(width 0.18288)
		(layer "In4.Cu")
		(net "M_B_CPU0_SB_DQ<25>")
	)
	(segment
		(start 296.71137 -203.521564)
		(end 296.38625 -203.521564)
		(width 0.18288)
		(layer "In4.Cu")
		(net "M_B_CPU0_SB_DQ<25>")
	)
	(segment
		(start 330.928218 -224.395792)
		(end 330.648564 -224.395792)
		(width 0.088646)
		(layer "In4.Cu")
		(net "M_B_CPU0_SB_DQ<25>")
	)
	(segment
		(start 296.20337 -203.02474)
		(end 296.02049 -202.84186)
		(width 0.18288)
		(layer "In4.Cu")
		(net "M_B_CPU0_SB_DQ<25>")
	)
	(segment
		(start 330.648564 -224.395792)
		(end 327.793604 -224.395792)
		(width 0.18288)
		(layer "In4.Cu")
		(net "M_B_CPU0_SB_DQ<25>")
	)
	(segment
		(start 297.58513 -203.02474)
		(end 297.40225 -202.84186)
		(width 0.18288)
		(layer "In4.Cu")
		(net "M_B_CPU0_SB_DQ<25>")
	)
	(segment
		(start 305.907694 -202.186032)
		(end 305.209448 -202.186032)
		(width 0.18288)
		(layer "In4.Cu")
		(net "M_B_CPU0_SB_DQ<25>")
	)
	(segment
		(start 333.26578 -226.017328)
		(end 332.351634 -226.017328)
		(width 0.088646)
		(layer "In4.Cu")
		(net "M_B_CPU0_SB_DQ<25>")
	)
	(segment
		(start 297.07713 -202.84186)
		(end 296.89425 -203.02474)
		(width 0.18288)
		(layer "In4.Cu")
		(net "M_B_CPU0_SB_DQ<25>")
	)
	(segment
		(start 298.27601 -203.338684)
		(end 298.09313 -203.521564)
		(width 0.18288)
		(layer "In4.Cu")
		(net "M_B_CPU0_SB_DQ<25>")
	)
	(segment
		(start 311.20588 -202.771248)
		(end 311.20588 -202.310492)
		(width 0.18288)
		(layer "In4.Cu")
		(net "M_B_CPU0_SB_DQ<25>")
	)
	(segment
		(start 306.181506 -201.91222)
		(end 305.907694 -202.186032)
		(width 0.18288)
		(layer "In4.Cu")
		(net "M_B_CPU0_SB_DQ<25>")
	)
	(segment
		(start 331.666088 -225.331782)
		(end 331.666088 -225.133662)
		(width 0.088646)
		(layer "In4.Cu")
		(net "M_B_CPU0_SB_DQ<25>")
	)
	(segment
		(start 298.09313 -203.521564)
		(end 297.76801 -203.521564)
		(width 0.18288)
		(layer "In4.Cu")
		(net "M_B_CPU0_SB_DQ<25>")
	)
	(segment
		(start 307.289962 -201.91222)
		(end 306.181506 -201.91222)
		(width 0.18288)
		(layer "In4.Cu")
		(net "M_B_CPU0_SB_DQ<25>")
	)
	(segment
		(start 304.444654 -202.950826)
		(end 303.88687 -202.950826)
		(width 0.18288)
		(layer "In4.Cu")
		(net "M_B_CPU0_SB_DQ<25>")
	)
	(segment
		(start 312.940954 -203.535026)
		(end 312.414158 -203.00823)
		(width 0.18288)
		(layer "In4.Cu")
		(net "M_B_CPU0_SB_DQ<25>")
	)
	(segment
		(start 333.735934 -227.367084)
		(end 333.735934 -226.831144)
		(width 0.20066)
		(layer "F.Cu")
		(net "M_B_CPU0_SB_DQ<24>")
	)
	(segment
		(start 287.589976 -204.116686)
		(end 286.255714 -204.116686)
		(width 0.20066)
		(layer "F.Cu")
		(net "M_B_CPU0_SB_DQ<24>")
	)
	(segment
		(start 291.556694 -203.691744)
		(end 289.48761 -203.691744)
		(width 0.1016)
		(layer "F.Cu")
		(net "M_B_CPU0_SB_DQ<24>")
	)
	(segment
		(start 294.904414 -204.116686)
		(end 293.799514 -204.116686)
		(width 0.20066)
		(layer "F.Cu")
		(net "M_B_CPU0_SB_DQ<24>")
	)
	(segment
		(start 288.46018 -203.893166)
		(end 288.46018 -204.182726)
		(width 0.20066)
		(layer "F.Cu")
		(net "M_B_CPU0_SB_DQ<24>")
	)
	(segment
		(start 288.28746 -204.355446)
		(end 287.828736 -204.355446)
		(width 0.20066)
		(layer "F.Cu")
		(net "M_B_CPU0_SB_DQ<24>")
	)
	(segment
		(start 289.239706 -203.691744)
		(end 289.231578 -203.683616)
		(width 0.101854)
		(layer "F.Cu")
		(net "M_B_CPU0_SB_DQ<24>")
	)
	(segment
		(start 288.66973 -203.683616)
		(end 288.46018 -203.893166)
		(width 0.20066)
		(layer "F.Cu")
		(net "M_B_CPU0_SB_DQ<24>")
	)
	(segment
		(start 292.005512 -203.691744)
		(end 291.556694 -203.691744)
		(width 0.20066)
		(layer "F.Cu")
		(net "M_B_CPU0_SB_DQ<24>")
	)
	(segment
		(start 289.48761 -203.691744)
		(end 289.239706 -203.691744)
		(width 0.101854)
		(layer "F.Cu")
		(net "M_B_CPU0_SB_DQ<24>")
	)
	(segment
		(start 293.799514 -204.116686)
		(end 292.430454 -204.116686)
		(width 0.20066)
		(layer "F.Cu")
		(net "M_B_CPU0_SB_DQ<24>")
	)
	(segment
		(start 288.46018 -204.182726)
		(end 288.28746 -204.355446)
		(width 0.20066)
		(layer "F.Cu")
		(net "M_B_CPU0_SB_DQ<24>")
	)
	(segment
		(start 289.231578 -203.683616)
		(end 288.66973 -203.683616)
		(width 0.20066)
		(layer "F.Cu")
		(net "M_B_CPU0_SB_DQ<24>")
	)
	(segment
		(start 287.828736 -204.355446)
		(end 287.589976 -204.116686)
		(width 0.20066)
		(layer "F.Cu")
		(net "M_B_CPU0_SB_DQ<24>")
	)
	(segment
		(start 292.430454 -204.116686)
		(end 292.005512 -203.691744)
		(width 0.20066)
		(layer "F.Cu")
		(net "M_B_CPU0_SB_DQ<24>")
	)
	(segment
		(start 313.868562 -205.259686)
		(end 313.866022 -205.262226)
		(width 0.18288)
		(layer "In4.Cu")
		(net "M_B_CPU0_SB_DQ<24>")
	)
	(segment
		(start 296.71645 -205.297024)
		(end 296.39133 -205.297024)
		(width 0.18288)
		(layer "In4.Cu")
		(net "M_B_CPU0_SB_DQ<24>")
	)
	(segment
		(start 298.093384 -204.38745)
		(end 297.241722 -204.38745)
		(width 0.18288)
		(layer "In4.Cu")
		(net "M_B_CPU0_SB_DQ<24>")
	)
	(segment
		(start 307.13934 -204.594206)
		(end 306.97932 -204.754226)
		(width 0.18288)
		(layer "In4.Cu")
		(net "M_B_CPU0_SB_DQ<24>")
	)
	(segment
		(start 333.735934 -226.831144)
		(end 334.048608 -226.831144)
		(width 0.088646)
		(layer "In4.Cu")
		(net "M_B_CPU0_SB_DQ<24>")
	)
	(segment
		(start 334.048608 -226.831144)
		(end 334.105758 -226.773994)
		(width 0.088646)
		(layer "In4.Cu")
		(net "M_B_CPU0_SB_DQ<24>")
	)
	(segment
		(start 301.014638 -204.668628)
		(end 300.704504 -204.358494)
		(width 0.18288)
		(layer "In4.Cu")
		(net "M_B_CPU0_SB_DQ<24>")
	)
	(segment
		(start 314.673742 -205.259686)
		(end 313.868562 -205.259686)
		(width 0.18288)
		(layer "In4.Cu")
		(net "M_B_CPU0_SB_DQ<24>")
	)
	(segment
		(start 313.866022 -205.262226)
		(end 311.707784 -205.262226)
		(width 0.18288)
		(layer "In4.Cu")
		(net "M_B_CPU0_SB_DQ<24>")
	)
	(segment
		(start 330.648564 -225.391472)
		(end 327.302368 -225.391472)
		(width 0.18288)
		(layer "In4.Cu")
		(net "M_B_CPU0_SB_DQ<24>")
	)
	(segment
		(start 306.97932 -204.754226)
		(end 303.938178 -204.754226)
		(width 0.18288)
		(layer "In4.Cu")
		(net "M_B_CPU0_SB_DQ<24>")
	)
	(segment
		(start 301.708058 -204.358494)
		(end 301.397924 -204.668628)
		(width 0.18288)
		(layer "In4.Cu")
		(net "M_B_CPU0_SB_DQ<24>")
	)
	(segment
		(start 296.89933 -205.114144)
		(end 296.71645 -205.297024)
		(width 0.18288)
		(layer "In4.Cu")
		(net "M_B_CPU0_SB_DQ<24>")
	)
	(segment
		(start 296.02557 -204.546962)
		(end 295.33469 -204.546962)
		(width 0.18288)
		(layer "In4.Cu")
		(net "M_B_CPU0_SB_DQ<24>")
	)
	(segment
		(start 296.39133 -205.297024)
		(end 296.20845 -205.114144)
		(width 0.18288)
		(layer "In4.Cu")
		(net "M_B_CPU0_SB_DQ<24>")
	)
	(segment
		(start 298.79163 -203.689204)
		(end 298.093384 -204.38745)
		(width 0.18288)
		(layer "In4.Cu")
		(net "M_B_CPU0_SB_DQ<24>")
	)
	(segment
		(start 296.89933 -204.729842)
		(end 296.89933 -205.114144)
		(width 0.18288)
		(layer "In4.Cu")
		(net "M_B_CPU0_SB_DQ<24>")
	)
	(segment
		(start 307.13934 -204.312266)
		(end 307.13934 -204.594206)
		(width 0.18288)
		(layer "In4.Cu")
		(net "M_B_CPU0_SB_DQ<24>")
	)
	(segment
		(start 303.938178 -204.754226)
		(end 303.542446 -204.358494)
		(width 0.18288)
		(layer "In4.Cu")
		(net "M_B_CPU0_SB_DQ<24>")
	)
	(segment
		(start 300.704504 -204.358494)
		(end 299.889164 -204.358494)
		(width 0.18288)
		(layer "In4.Cu")
		(net "M_B_CPU0_SB_DQ<24>")
	)
	(segment
		(start 322.223638 -220.312742)
		(end 316.917832 -207.503776)
		(width 0.18288)
		(layer "In4.Cu")
		(net "M_B_CPU0_SB_DQ<24>")
	)
	(segment
		(start 332.100428 -226.521772)
		(end 330.970128 -225.391472)
		(width 0.088646)
		(layer "In4.Cu")
		(net "M_B_CPU0_SB_DQ<24>")
	)
	(segment
		(start 327.302368 -225.391472)
		(end 322.223638 -220.312742)
		(width 0.18288)
		(layer "In4.Cu")
		(net "M_B_CPU0_SB_DQ<24>")
	)
	(segment
		(start 316.917832 -207.503776)
		(end 314.673742 -205.259686)
		(width 0.18288)
		(layer "In4.Cu")
		(net "M_B_CPU0_SB_DQ<24>")
	)
	(segment
		(start 308.342284 -204.45603)
		(end 308.0385 -204.152246)
		(width 0.18288)
		(layer "In4.Cu")
		(net "M_B_CPU0_SB_DQ<24>")
	)
	(segment
		(start 299.219874 -203.689204)
		(end 298.79163 -203.689204)
		(width 0.18288)
		(layer "In4.Cu")
		(net "M_B_CPU0_SB_DQ<24>")
	)
	(segment
		(start 303.542446 -204.358494)
		(end 301.708058 -204.358494)
		(width 0.18288)
		(layer "In4.Cu")
		(net "M_B_CPU0_SB_DQ<24>")
	)
	(segment
		(start 295.33469 -204.546962)
		(end 294.904414 -204.116686)
		(width 0.18288)
		(layer "In4.Cu")
		(net "M_B_CPU0_SB_DQ<24>")
	)
	(segment
		(start 330.970128 -225.391472)
		(end 330.648564 -225.391472)
		(width 0.088646)
		(layer "In4.Cu")
		(net "M_B_CPU0_SB_DQ<24>")
	)
	(segment
		(start 308.0385 -204.152246)
		(end 307.29936 -204.152246)
		(width 0.18288)
		(layer "In4.Cu")
		(net "M_B_CPU0_SB_DQ<24>")
	)
	(segment
		(start 297.241722 -204.38745)
		(end 296.89933 -204.729842)
		(width 0.18288)
		(layer "In4.Cu")
		(net "M_B_CPU0_SB_DQ<24>")
	)
	(segment
		(start 296.20845 -204.729842)
		(end 296.02557 -204.546962)
		(width 0.18288)
		(layer "In4.Cu")
		(net "M_B_CPU0_SB_DQ<24>")
	)
	(segment
		(start 311.707784 -205.262226)
		(end 310.901588 -204.45603)
		(width 0.18288)
		(layer "In4.Cu")
		(net "M_B_CPU0_SB_DQ<24>")
	)
	(segment
		(start 332.511146 -226.521772)
		(end 332.100428 -226.521772)
		(width 0.088646)
		(layer "In4.Cu")
		(net "M_B_CPU0_SB_DQ<24>")
	)
	(segment
		(start 296.20845 -205.114144)
		(end 296.20845 -204.729842)
		(width 0.18288)
		(layer "In4.Cu")
		(net "M_B_CPU0_SB_DQ<24>")
	)
	(segment
		(start 299.889164 -204.358494)
		(end 299.219874 -203.689204)
		(width 0.18288)
		(layer "In4.Cu")
		(net "M_B_CPU0_SB_DQ<24>")
	)
	(segment
		(start 307.29936 -204.152246)
		(end 307.13934 -204.312266)
		(width 0.18288)
		(layer "In4.Cu")
		(net "M_B_CPU0_SB_DQ<24>")
	)
	(segment
		(start 301.397924 -204.668628)
		(end 301.014638 -204.668628)
		(width 0.18288)
		(layer "In4.Cu")
		(net "M_B_CPU0_SB_DQ<24>")
	)
	(segment
		(start 332.993492 -226.512882)
		(end 332.983078 -226.506786)
		(width 0.088646)
		(layer "In4.Cu")
		(net "M_B_CPU0_SB_DQ<24>")
	)
	(segment
		(start 310.901588 -204.45603)
		(end 308.342284 -204.45603)
		(width 0.18288)
		(layer "In4.Cu")
		(net "M_B_CPU0_SB_DQ<24>")
	)
	(arc
		(start 333.548736 -226.506786)
		(mid 333.271923 -226.582656)
		(end 332.993492 -226.512882)
		(width 0.088646)
		(layer "In4.Cu")
		(net "M_B_CPU0_SB_DQ<24>")
	)
	(arc
		(start 332.983078 -226.506786)
		(mid 332.809431 -226.456736)
		(end 332.632558 -226.493832)
		(width 0.088646)
		(layer "In4.Cu")
		(net "M_B_CPU0_SB_DQ<24>")
	)
	(arc
		(start 334.105758 -226.773994)
		(mid 334.044815 -226.619631)
		(end 333.923132 -226.506786)
		(width 0.088646)
		(layer "In4.Cu")
		(net "M_B_CPU0_SB_DQ<24>")
	)
	(arc
		(start 333.923132 -226.506786)
		(mid 333.735934 -226.456643)
		(end 333.548736 -226.506786)
		(width 0.088646)
		(layer "In4.Cu")
		(net "M_B_CPU0_SB_DQ<24>")
	)
	(arc
		(start 332.632558 -226.493832)
		(mid 332.573435 -226.51467)
		(end 332.511146 -226.521772)
		(width 0.088646)
		(layer "In4.Cu")
		(net "M_B_CPU0_SB_DQ<24>")
	)
	(segment
		(start 292.321488 -205.405736)
		(end 292.178994 -205.263242)
		(width 0.20066)
		(layer "F.Cu")
		(net "M_B_CPU0_SB_DQ<23>")
	)
	(segment
		(start 337.965034 -226.553014)
		(end 337.965034 -226.017328)
		(width 0.20066)
		(layer "F.Cu")
		(net "M_B_CPU0_SB_DQ<23>")
	)
	(segment
		(start 292.927532 -205.391512)
		(end 292.689534 -205.391512)
		(width 0.101854)
		(layer "F.Cu")
		(net "M_B_CPU0_SB_DQ<23>")
	)
	(segment
		(start 292.67531 -205.405736)
		(end 292.321488 -205.405736)
		(width 0.20066)
		(layer "F.Cu")
		(net "M_B_CPU0_SB_DQ<23>")
	)
	(segment
		(start 292.178994 -205.263242)
		(end 292.178994 -205.092554)
		(width 0.20066)
		(layer "F.Cu")
		(net "M_B_CPU0_SB_DQ<23>")
	)
	(segment
		(start 296.217594 -204.962252)
		(end 295.82237 -204.962252)
		(width 0.20066)
		(layer "F.Cu")
		(net "M_B_CPU0_SB_DQ<23>")
	)
	(segment
		(start 295.693846 -205.242414)
		(end 295.544748 -205.391512)
		(width 0.20066)
		(layer "F.Cu")
		(net "M_B_CPU0_SB_DQ<23>")
	)
	(segment
		(start 295.544748 -205.391512)
		(end 295.000426 -205.391512)
		(width 0.20066)
		(layer "F.Cu")
		(net "M_B_CPU0_SB_DQ<23>")
	)
	(segment
		(start 299.004482 -204.96657)
		(end 297.899582 -204.96657)
		(width 0.20066)
		(layer "F.Cu")
		(net "M_B_CPU0_SB_DQ<23>")
	)
	(segment
		(start 296.875962 -205.174088)
		(end 296.42943 -205.174088)
		(width 0.20066)
		(layer "F.Cu")
		(net "M_B_CPU0_SB_DQ<23>")
	)
	(segment
		(start 297.899582 -204.96657)
		(end 297.08348 -204.96657)
		(width 0.20066)
		(layer "F.Cu")
		(net "M_B_CPU0_SB_DQ<23>")
	)
	(segment
		(start 295.82237 -204.962252)
		(end 295.693846 -205.090776)
		(width 0.20066)
		(layer "F.Cu")
		(net "M_B_CPU0_SB_DQ<23>")
	)
	(segment
		(start 337.96478 -226.553268)
		(end 337.965034 -226.553014)
		(width 0.20066)
		(layer "F.Cu")
		(net "M_B_CPU0_SB_DQ<23>")
	)
	(segment
		(start 292.05301 -204.96657)
		(end 290.355782 -204.96657)
		(width 0.20066)
		(layer "F.Cu")
		(net "M_B_CPU0_SB_DQ<23>")
	)
	(segment
		(start 295.000426 -205.391512)
		(end 292.927532 -205.391512)
		(width 0.1016)
		(layer "F.Cu")
		(net "M_B_CPU0_SB_DQ<23>")
	)
	(segment
		(start 292.689534 -205.391512)
		(end 292.67531 -205.405736)
		(width 0.101854)
		(layer "F.Cu")
		(net "M_B_CPU0_SB_DQ<23>")
	)
	(segment
		(start 297.08348 -204.96657)
		(end 296.875962 -205.174088)
		(width 0.20066)
		(layer "F.Cu")
		(net "M_B_CPU0_SB_DQ<23>")
	)
	(segment
		(start 296.42943 -205.174088)
		(end 296.217594 -204.962252)
		(width 0.20066)
		(layer "F.Cu")
		(net "M_B_CPU0_SB_DQ<23>")
	)
	(segment
		(start 295.693846 -205.090776)
		(end 295.693846 -205.242414)
		(width 0.20066)
		(layer "F.Cu")
		(net "M_B_CPU0_SB_DQ<23>")
	)
	(segment
		(start 292.178994 -205.092554)
		(end 292.05301 -204.96657)
		(width 0.20066)
		(layer "F.Cu")
		(net "M_B_CPU0_SB_DQ<23>")
	)
	(segment
		(start 335.436972 -222.276924)
		(end 335.428336 -222.272098)
		(width 0.088646)
		(layer "In2.Cu")
		(net "M_B_CPU0_SB_DQ<23>")
	)
	(segment
		(start 337.777836 -224.7138)
		(end 337.768946 -224.70872)
		(width 0.088646)
		(layer "In2.Cu")
		(net "M_B_CPU0_SB_DQ<23>")
	)
	(segment
		(start 306.774088 -203.686664)
		(end 303.46142 -203.686664)
		(width 0.18288)
		(layer "In2.Cu")
		(net "M_B_CPU0_SB_DQ<23>")
	)
	(segment
		(start 336.272632 -223.085914)
		(end 336.26425 -223.09074)
		(width 0.088646)
		(layer "In2.Cu")
		(net "M_B_CPU0_SB_DQ<23>")
	)
	(segment
		(start 335.428336 -222.272098)
		(end 335.419446 -222.267018)
		(width 0.088646)
		(layer "In2.Cu")
		(net "M_B_CPU0_SB_DQ<23>")
	)
	(segment
		(start 309.982108 -203.90485)
		(end 309.635906 -203.558648)
		(width 0.18288)
		(layer "In2.Cu")
		(net "M_B_CPU0_SB_DQ<23>")
	)
	(segment
		(start 303.26838 -203.879704)
		(end 303.26838 -204.229462)
		(width 0.18288)
		(layer "In2.Cu")
		(net "M_B_CPU0_SB_DQ<23>")
	)
	(segment
		(start 311.244234 -204.15123)
		(end 310.794146 -204.15123)
		(width 0.18288)
		(layer "In2.Cu")
		(net "M_B_CPU0_SB_DQ<23>")
	)
	(segment
		(start 337.965034 -226.017328)
		(end 337.65236 -226.017328)
		(width 0.088646)
		(layer "In2.Cu")
		(net "M_B_CPU0_SB_DQ<23>")
	)
	(segment
		(start 302.67275 -204.336142)
		(end 302.3997 -204.336142)
		(width 0.18288)
		(layer "In2.Cu")
		(net "M_B_CPU0_SB_DQ<23>")
	)
	(segment
		(start 315.325252 -203.863448)
		(end 315.132212 -203.670408)
		(width 0.18288)
		(layer "In2.Cu")
		(net "M_B_CPU0_SB_DQ<23>")
	)
	(segment
		(start 333.703422 -219.905834)
		(end 332.969362 -219.905834)
		(width 0.18288)
		(layer "In2.Cu")
		(net "M_B_CPU0_SB_DQ<23>")
	)
	(segment
		(start 316.22873 -203.882752)
		(end 316.22873 -204.71003)
		(width 0.18288)
		(layer "In2.Cu")
		(net "M_B_CPU0_SB_DQ<23>")
	)
	(segment
		(start 310.794146 -204.15123)
		(end 310.547766 -203.90485)
		(width 0.18288)
		(layer "In2.Cu")
		(net "M_B_CPU0_SB_DQ<23>")
	)
	(segment
		(start 303.05375 -204.444092)
		(end 302.7807 -204.444092)
		(width 0.18288)
		(layer "In2.Cu")
		(net "M_B_CPU0_SB_DQ<23>")
	)
	(segment
		(start 337.307936 -223.899984)
		(end 337.299046 -223.894904)
		(width 0.088646)
		(layer "In2.Cu")
		(net "M_B_CPU0_SB_DQ<23>")
	)
	(segment
		(start 311.581546 -203.55941)
		(end 311.418986 -203.72197)
		(width 0.18288)
		(layer "In2.Cu")
		(net "M_B_CPU0_SB_DQ<23>")
	)
	(segment
		(start 335.89849 -223.085914)
		(end 335.8896 -223.080834)
		(width 0.088646)
		(layer "In2.Cu")
		(net "M_B_CPU0_SB_DQ<23>")
	)
	(segment
		(start 337.65236 -226.017328)
		(end 337.594956 -225.959924)
		(width 0.088646)
		(layer "In2.Cu")
		(net "M_B_CPU0_SB_DQ<23>")
	)
	(segment
		(start 334.177894 -220.380306)
		(end 333.703422 -219.905834)
		(width 0.18288)
		(layer "In2.Cu")
		(net "M_B_CPU0_SB_DQ<23>")
	)
	(segment
		(start 315.132212 -203.670408)
		(end 313.900312 -203.670408)
		(width 0.18288)
		(layer "In2.Cu")
		(net "M_B_CPU0_SB_DQ<23>")
	)
	(segment
		(start 312.05043 -203.55941)
		(end 311.581546 -203.55941)
		(width 0.18288)
		(layer "In2.Cu")
		(net "M_B_CPU0_SB_DQ<23>")
	)
	(segment
		(start 334.710532 -220.912944)
		(end 334.177894 -220.380306)
		(width 0.088646)
		(layer "In2.Cu")
		(net "M_B_CPU0_SB_DQ<23>")
	)
	(segment
		(start 311.418986 -203.976478)
		(end 311.244234 -204.15123)
		(width 0.18288)
		(layer "In2.Cu")
		(net "M_B_CPU0_SB_DQ<23>")
	)
	(segment
		(start 337.768946 -225.69805)
		(end 337.777836 -225.69297)
		(width 0.088646)
		(layer "In2.Cu")
		(net "M_B_CPU0_SB_DQ<23>")
	)
	(segment
		(start 299.44568 -204.525372)
		(end 299.004482 -204.96657)
		(width 0.18288)
		(layer "In2.Cu")
		(net "M_B_CPU0_SB_DQ<23>")
	)
	(segment
		(start 315.518292 -204.90307)
		(end 315.325252 -204.71003)
		(width 0.18288)
		(layer "In2.Cu")
		(net "M_B_CPU0_SB_DQ<23>")
	)
	(segment
		(start 332.969362 -219.905834)
		(end 317.966598 -204.90307)
		(width 0.18288)
		(layer "In2.Cu")
		(net "M_B_CPU0_SB_DQ<23>")
	)
	(segment
		(start 317.966598 -204.90307)
		(end 317.226696 -204.90307)
		(width 0.18288)
		(layer "In2.Cu")
		(net "M_B_CPU0_SB_DQ<23>")
	)
	(segment
		(start 310.547766 -203.90485)
		(end 309.982108 -203.90485)
		(width 0.18288)
		(layer "In2.Cu")
		(net "M_B_CPU0_SB_DQ<23>")
	)
	(segment
		(start 334.710532 -221.183962)
		(end 334.710532 -220.912944)
		(width 0.088646)
		(layer "In2.Cu")
		(net "M_B_CPU0_SB_DQ<23>")
	)
	(segment
		(start 337.120484 -223.575626)
		(end 337.120484 -223.561402)
		(width 0.088646)
		(layer "In2.Cu")
		(net "M_B_CPU0_SB_DQ<23>")
	)
	(segment
		(start 335.440528 -222.27921)
		(end 335.436972 -222.276924)
		(width 0.088646)
		(layer "In2.Cu")
		(net "M_B_CPU0_SB_DQ<23>")
	)
	(segment
		(start 315.325252 -204.71003)
		(end 315.325252 -203.863448)
		(width 0.18288)
		(layer "In2.Cu")
		(net "M_B_CPU0_SB_DQ<23>")
	)
	(segment
		(start 308.138322 -203.558648)
		(end 307.70576 -203.99121)
		(width 0.18288)
		(layer "In2.Cu")
		(net "M_B_CPU0_SB_DQ<23>")
	)
	(segment
		(start 316.03569 -204.90307)
		(end 315.518292 -204.90307)
		(width 0.18288)
		(layer "In2.Cu")
		(net "M_B_CPU0_SB_DQ<23>")
	)
	(segment
		(start 335.240884 -221.94774)
		(end 335.240884 -221.937834)
		(width 0.088646)
		(layer "In2.Cu")
		(net "M_B_CPU0_SB_DQ<23>")
	)
	(segment
		(start 313.900312 -203.670408)
		(end 313.643518 -203.927202)
		(width 0.18288)
		(layer "In2.Cu")
		(net "M_B_CPU0_SB_DQ<23>")
	)
	(segment
		(start 316.840616 -203.689458)
		(end 316.422024 -203.689458)
		(width 0.18288)
		(layer "In2.Cu")
		(net "M_B_CPU0_SB_DQ<23>")
	)
	(segment
		(start 338.06003 -225.225356)
		(end 338.06003 -225.187764)
		(width 0.088646)
		(layer "In2.Cu")
		(net "M_B_CPU0_SB_DQ<23>")
	)
	(segment
		(start 336.287364 -223.077278)
		(end 336.272632 -223.085914)
		(width 0.088646)
		(layer "In2.Cu")
		(net "M_B_CPU0_SB_DQ<23>")
	)
	(segment
		(start 309.635906 -203.558648)
		(end 308.138322 -203.558648)
		(width 0.18288)
		(layer "In2.Cu")
		(net "M_B_CPU0_SB_DQ<23>")
	)
	(segment
		(start 313.643518 -203.927202)
		(end 312.418222 -203.927202)
		(width 0.18288)
		(layer "In2.Cu")
		(net "M_B_CPU0_SB_DQ<23>")
	)
	(segment
		(start 302.7807 -204.444092)
		(end 302.67275 -204.336142)
		(width 0.18288)
		(layer "In2.Cu")
		(net "M_B_CPU0_SB_DQ<23>")
	)
	(segment
		(start 316.22873 -204.71003)
		(end 316.03569 -204.90307)
		(width 0.18288)
		(layer "In2.Cu")
		(net "M_B_CPU0_SB_DQ<23>")
	)
	(segment
		(start 303.46142 -203.686664)
		(end 303.26838 -203.879704)
		(width 0.18288)
		(layer "In2.Cu")
		(net "M_B_CPU0_SB_DQ<23>")
	)
	(segment
		(start 302.3997 -204.336142)
		(end 302.21047 -204.525372)
		(width 0.18288)
		(layer "In2.Cu")
		(net "M_B_CPU0_SB_DQ<23>")
	)
	(segment
		(start 316.422024 -203.689458)
		(end 316.22873 -203.882752)
		(width 0.18288)
		(layer "In2.Cu")
		(net "M_B_CPU0_SB_DQ<23>")
	)
	(segment
		(start 311.418986 -203.72197)
		(end 311.418986 -203.976478)
		(width 0.18288)
		(layer "In2.Cu")
		(net "M_B_CPU0_SB_DQ<23>")
	)
	(segment
		(start 335.057242 -221.530672)
		(end 334.710532 -221.183962)
		(width 0.088646)
		(layer "In2.Cu")
		(net "M_B_CPU0_SB_DQ<23>")
	)
	(segment
		(start 303.26838 -204.229462)
		(end 303.05375 -204.444092)
		(width 0.18288)
		(layer "In2.Cu")
		(net "M_B_CPU0_SB_DQ<23>")
	)
	(segment
		(start 312.418222 -203.927202)
		(end 312.05043 -203.55941)
		(width 0.18288)
		(layer "In2.Cu")
		(net "M_B_CPU0_SB_DQ<23>")
	)
	(segment
		(start 317.226696 -204.90307)
		(end 317.033656 -204.71003)
		(width 0.18288)
		(layer "In2.Cu")
		(net "M_B_CPU0_SB_DQ<23>")
	)
	(segment
		(start 302.21047 -204.525372)
		(end 299.44568 -204.525372)
		(width 0.18288)
		(layer "In2.Cu")
		(net "M_B_CPU0_SB_DQ<23>")
	)
	(segment
		(start 337.590384 -224.389442)
		(end 337.590384 -224.379536)
		(width 0.088646)
		(layer "In2.Cu")
		(net "M_B_CPU0_SB_DQ<23>")
	)
	(segment
		(start 317.033656 -203.882498)
		(end 316.840616 -203.689458)
		(width 0.18288)
		(layer "In2.Cu")
		(net "M_B_CPU0_SB_DQ<23>")
	)
	(segment
		(start 307.70576 -203.99121)
		(end 307.078634 -203.99121)
		(width 0.18288)
		(layer "In2.Cu")
		(net "M_B_CPU0_SB_DQ<23>")
	)
	(segment
		(start 307.078634 -203.99121)
		(end 306.774088 -203.686664)
		(width 0.18288)
		(layer "In2.Cu")
		(net "M_B_CPU0_SB_DQ<23>")
	)
	(segment
		(start 317.033656 -204.71003)
		(end 317.033656 -203.882498)
		(width 0.18288)
		(layer "In2.Cu")
		(net "M_B_CPU0_SB_DQ<23>")
	)
	(arc
		(start 335.8896 -223.080834)
		(mid 335.758686 -222.944474)
		(end 335.711038 -222.761556)
		(width 0.088646)
		(layer "In2.Cu")
		(net "M_B_CPU0_SB_DQ<23>")
	)
	(arc
		(start 335.711038 -222.761556)
		(mid 335.638803 -222.485032)
		(end 335.440528 -222.27921)
		(width 0.088646)
		(layer "In2.Cu")
		(net "M_B_CPU0_SB_DQ<23>")
	)
	(arc
		(start 337.120484 -223.561402)
		(mid 337.041343 -223.286779)
		(end 336.838036 -223.085914)
		(width 0.088646)
		(layer "In2.Cu")
		(net "M_B_CPU0_SB_DQ<23>")
	)
	(arc
		(start 335.419446 -222.267018)
		(mid 335.288532 -222.130658)
		(end 335.240884 -221.94774)
		(width 0.088646)
		(layer "In2.Cu")
		(net "M_B_CPU0_SB_DQ<23>")
	)
	(arc
		(start 336.838036 -223.085914)
		(mid 336.563807 -223.009989)
		(end 336.287364 -223.077278)
		(width 0.088646)
		(layer "In2.Cu")
		(net "M_B_CPU0_SB_DQ<23>")
	)
	(arc
		(start 337.590384 -224.379536)
		(mid 337.512273 -224.102587)
		(end 337.307936 -223.899984)
		(width 0.088646)
		(layer "In2.Cu")
		(net "M_B_CPU0_SB_DQ<23>")
	)
	(arc
		(start 337.777836 -225.69297)
		(mid 337.979118 -225.495483)
		(end 338.06003 -225.225356)
		(width 0.088646)
		(layer "In2.Cu")
		(net "M_B_CPU0_SB_DQ<23>")
	)
	(arc
		(start 337.299046 -223.894904)
		(mid 337.168132 -223.758544)
		(end 337.120484 -223.575626)
		(width 0.088646)
		(layer "In2.Cu")
		(net "M_B_CPU0_SB_DQ<23>")
	)
	(arc
		(start 335.240884 -221.937834)
		(mid 335.190986 -221.715344)
		(end 335.057242 -221.530672)
		(width 0.088646)
		(layer "In2.Cu")
		(net "M_B_CPU0_SB_DQ<23>")
	)
	(arc
		(start 337.594956 -225.959924)
		(mid 337.653112 -225.809811)
		(end 337.768946 -225.69805)
		(width 0.088646)
		(layer "In2.Cu")
		(net "M_B_CPU0_SB_DQ<23>")
	)
	(arc
		(start 336.26425 -223.09074)
		(mid 336.080742 -223.136018)
		(end 335.89849 -223.085914)
		(width 0.088646)
		(layer "In2.Cu")
		(net "M_B_CPU0_SB_DQ<23>")
	)
	(arc
		(start 338.06003 -225.187764)
		(mid 337.98066 -224.91403)
		(end 337.777836 -224.7138)
		(width 0.088646)
		(layer "In2.Cu")
		(net "M_B_CPU0_SB_DQ<23>")
	)
	(arc
		(start 337.768946 -224.70872)
		(mid 337.638032 -224.57236)
		(end 337.590384 -224.389442)
		(width 0.088646)
		(layer "In2.Cu")
		(net "M_B_CPU0_SB_DQ<23>")
	)
	(segment
		(start 295.777158 -206.711042)
		(end 295.777158 -206.385414)
		(width 0.20066)
		(layer "F.Cu")
		(net "M_B_CPU0_SB_DQ<22>")
	)
	(segment
		(start 295.944544 -206.878428)
		(end 295.777158 -206.711042)
		(width 0.20066)
		(layer "F.Cu")
		(net "M_B_CPU0_SB_DQ<22>")
	)
	(segment
		(start 338.43468 -227.36683)
		(end 338.43468 -226.831144)
		(width 0.20066)
		(layer "F.Cu")
		(net "M_B_CPU0_SB_DQ<22>")
	)
	(segment
		(start 291.937948 -206.23149)
		(end 291.502846 -206.666592)
		(width 0.20066)
		(layer "F.Cu")
		(net "M_B_CPU0_SB_DQ<22>")
	)
	(segment
		(start 297.899582 -206.666592)
		(end 296.584878 -206.666592)
		(width 0.20066)
		(layer "F.Cu")
		(net "M_B_CPU0_SB_DQ<22>")
	)
	(segment
		(start 291.502846 -206.666592)
		(end 290.355782 -206.666592)
		(width 0.20066)
		(layer "F.Cu")
		(net "M_B_CPU0_SB_DQ<22>")
	)
	(segment
		(start 296.584878 -206.666592)
		(end 296.373042 -206.878428)
		(width 0.20066)
		(layer "F.Cu")
		(net "M_B_CPU0_SB_DQ<22>")
	)
	(segment
		(start 295.000426 -206.24165)
		(end 292.940486 -206.24165)
		(width 0.1016)
		(layer "F.Cu")
		(net "M_B_CPU0_SB_DQ<22>")
	)
	(segment
		(start 299.004482 -206.666592)
		(end 297.899582 -206.666592)
		(width 0.20066)
		(layer "F.Cu")
		(net "M_B_CPU0_SB_DQ<22>")
	)
	(segment
		(start 292.68547 -206.24165)
		(end 292.67531 -206.23149)
		(width 0.101854)
		(layer "F.Cu")
		(net "M_B_CPU0_SB_DQ<22>")
	)
	(segment
		(start 295.633394 -206.24165)
		(end 295.000426 -206.24165)
		(width 0.20066)
		(layer "F.Cu")
		(net "M_B_CPU0_SB_DQ<22>")
	)
	(segment
		(start 296.373042 -206.878428)
		(end 295.944544 -206.878428)
		(width 0.20066)
		(layer "F.Cu")
		(net "M_B_CPU0_SB_DQ<22>")
	)
	(segment
		(start 338.434934 -227.367084)
		(end 338.43468 -227.36683)
		(width 0.20066)
		(layer "F.Cu")
		(net "M_B_CPU0_SB_DQ<22>")
	)
	(segment
		(start 295.777158 -206.385414)
		(end 295.633394 -206.24165)
		(width 0.20066)
		(layer "F.Cu")
		(net "M_B_CPU0_SB_DQ<22>")
	)
	(segment
		(start 292.940486 -206.24165)
		(end 292.68547 -206.24165)
		(width 0.101854)
		(layer "F.Cu")
		(net "M_B_CPU0_SB_DQ<22>")
	)
	(segment
		(start 292.67531 -206.23149)
		(end 291.937948 -206.23149)
		(width 0.20066)
		(layer "F.Cu")
		(net "M_B_CPU0_SB_DQ<22>")
	)
	(segment
		(start 316.916816 -205.9432)
		(end 316.723776 -206.13624)
		(width 0.18288)
		(layer "In2.Cu")
		(net "M_B_CPU0_SB_DQ<22>")
	)
	(segment
		(start 334.273906 -222.075756)
		(end 334.273906 -221.914974)
		(width 0.088646)
		(layer "In2.Cu")
		(net "M_B_CPU0_SB_DQ<22>")
	)
	(segment
		(start 312.22442 -205.517242)
		(end 311.915048 -205.20787)
		(width 0.18288)
		(layer "In2.Cu")
		(net "M_B_CPU0_SB_DQ<22>")
	)
	(segment
		(start 304.055018 -205.337664)
		(end 303.849024 -205.543658)
		(width 0.18288)
		(layer "In2.Cu")
		(net "M_B_CPU0_SB_DQ<22>")
	)
	(segment
		(start 299.46981 -206.201264)
		(end 299.004482 -206.666592)
		(width 0.18288)
		(layer "In2.Cu")
		(net "M_B_CPU0_SB_DQ<22>")
	)
	(segment
		(start 336.829146 -225.69805)
		(end 336.838036 -225.69297)
		(width 0.088646)
		(layer "In2.Cu")
		(net "M_B_CPU0_SB_DQ<22>")
	)
	(segment
		(start 315.760608 -206.915766)
		(end 315.567568 -206.722726)
		(width 0.18288)
		(layer "In2.Cu")
		(net "M_B_CPU0_SB_DQ<22>")
	)
	(segment
		(start 334.770984 -222.761556)
		(end 334.770984 -222.75165)
		(width 0.088646)
		(layer "In2.Cu")
		(net "M_B_CPU0_SB_DQ<22>")
	)
	(segment
		(start 315.374528 -205.933548)
		(end 314.89904 -205.933548)
		(width 0.18288)
		(layer "In2.Cu")
		(net "M_B_CPU0_SB_DQ<22>")
	)
	(segment
		(start 314.292996 -205.327504)
		(end 313.865768 -205.327504)
		(width 0.18288)
		(layer "In2.Cu")
		(net "M_B_CPU0_SB_DQ<22>")
	)
	(segment
		(start 317.473584 -205.9432)
		(end 316.916816 -205.9432)
		(width 0.18288)
		(layer "In2.Cu")
		(net "M_B_CPU0_SB_DQ<22>")
	)
	(segment
		(start 310.548528 -205.20787)
		(end 310.355234 -205.401164)
		(width 0.18288)
		(layer "In2.Cu")
		(net "M_B_CPU0_SB_DQ<22>")
	)
	(segment
		(start 306.117498 -205.620112)
		(end 304.83429 -205.620112)
		(width 0.18288)
		(layer "In2.Cu")
		(net "M_B_CPU0_SB_DQ<22>")
	)
	(segment
		(start 308.310788 -205.109826)
		(end 307.89499 -205.525624)
		(width 0.18288)
		(layer "In2.Cu")
		(net "M_B_CPU0_SB_DQ<22>")
	)
	(segment
		(start 315.567568 -206.126588)
		(end 315.374528 -205.933548)
		(width 0.18288)
		(layer "In2.Cu")
		(net "M_B_CPU0_SB_DQ<22>")
	)
	(segment
		(start 332.496922 -220.956886)
		(end 318.4398 -206.899764)
		(width 0.18288)
		(layer "In2.Cu")
		(net "M_B_CPU0_SB_DQ<22>")
	)
	(segment
		(start 334.410812 -222.212662)
		(end 334.273906 -222.075756)
		(width 0.088646)
		(layer "In2.Cu")
		(net "M_B_CPU0_SB_DQ<22>")
	)
	(segment
		(start 336.838036 -224.7138)
		(end 336.829146 -224.70872)
		(width 0.088646)
		(layer "In2.Cu")
		(net "M_B_CPU0_SB_DQ<22>")
	)
	(segment
		(start 314.89904 -205.933548)
		(end 314.292996 -205.327504)
		(width 0.18288)
		(layer "In2.Cu")
		(net "M_B_CPU0_SB_DQ<22>")
	)
	(segment
		(start 317.859664 -206.899764)
		(end 317.666624 -206.706724)
		(width 0.18288)
		(layer "In2.Cu")
		(net "M_B_CPU0_SB_DQ<22>")
	)
	(segment
		(start 316.723776 -206.722726)
		(end 316.530736 -206.915766)
		(width 0.18288)
		(layer "In2.Cu")
		(net "M_B_CPU0_SB_DQ<22>")
	)
	(segment
		(start 316.530736 -206.915766)
		(end 315.760608 -206.915766)
		(width 0.18288)
		(layer "In2.Cu")
		(net "M_B_CPU0_SB_DQ<22>")
	)
	(segment
		(start 334.273906 -221.914974)
		(end 333.458566 -221.099634)
		(width 0.088646)
		(layer "In2.Cu")
		(net "M_B_CPU0_SB_DQ<22>")
	)
	(segment
		(start 334.958436 -223.085914)
		(end 334.949546 -223.080834)
		(width 0.088646)
		(layer "In2.Cu")
		(net "M_B_CPU0_SB_DQ<22>")
	)
	(segment
		(start 335.240884 -223.575626)
		(end 335.240884 -223.557084)
		(width 0.088646)
		(layer "In2.Cu")
		(net "M_B_CPU0_SB_DQ<22>")
	)
	(segment
		(start 336.367882 -223.899984)
		(end 336.357468 -223.893888)
		(width 0.088646)
		(layer "In2.Cu")
		(net "M_B_CPU0_SB_DQ<22>")
	)
	(segment
		(start 307.89499 -205.525624)
		(end 307.236876 -205.525624)
		(width 0.18288)
		(layer "In2.Cu")
		(net "M_B_CPU0_SB_DQ<22>")
	)
	(segment
		(start 304.551842 -205.337664)
		(end 304.055018 -205.337664)
		(width 0.18288)
		(layer "In2.Cu")
		(net "M_B_CPU0_SB_DQ<22>")
	)
	(segment
		(start 317.666624 -206.13624)
		(end 317.473584 -205.9432)
		(width 0.18288)
		(layer "In2.Cu")
		(net "M_B_CPU0_SB_DQ<22>")
	)
	(segment
		(start 337.120484 -225.2218)
		(end 337.120484 -225.193352)
		(width 0.088646)
		(layer "In2.Cu")
		(net "M_B_CPU0_SB_DQ<22>")
	)
	(segment
		(start 316.723776 -206.13624)
		(end 316.723776 -206.722726)
		(width 0.18288)
		(layer "In2.Cu")
		(net "M_B_CPU0_SB_DQ<22>")
	)
	(segment
		(start 317.666624 -206.706724)
		(end 317.666624 -206.13624)
		(width 0.18288)
		(layer "In2.Cu")
		(net "M_B_CPU0_SB_DQ<22>")
	)
	(segment
		(start 336.373978 -223.90354)
		(end 336.367882 -223.899984)
		(width 0.088646)
		(layer "In2.Cu")
		(net "M_B_CPU0_SB_DQ<22>")
	)
	(segment
		(start 336.838036 -226.341686)
		(end 336.829146 -226.336606)
		(width 0.088646)
		(layer "In2.Cu")
		(net "M_B_CPU0_SB_DQ<22>")
	)
	(segment
		(start 309.771542 -205.401164)
		(end 309.480204 -205.109826)
		(width 0.18288)
		(layer "In2.Cu")
		(net "M_B_CPU0_SB_DQ<22>")
	)
	(segment
		(start 333.315818 -220.956886)
		(end 332.496922 -220.956886)
		(width 0.18288)
		(layer "In2.Cu")
		(net "M_B_CPU0_SB_DQ<22>")
	)
	(segment
		(start 311.915048 -205.20787)
		(end 310.548528 -205.20787)
		(width 0.18288)
		(layer "In2.Cu")
		(net "M_B_CPU0_SB_DQ<22>")
	)
	(segment
		(start 302.435514 -206.043022)
		(end 302.068738 -206.409798)
		(width 0.18288)
		(layer "In2.Cu")
		(net "M_B_CPU0_SB_DQ<22>")
	)
	(segment
		(start 335.428336 -223.899984)
		(end 335.419446 -223.894904)
		(width 0.088646)
		(layer "In2.Cu")
		(net "M_B_CPU0_SB_DQ<22>")
	)
	(segment
		(start 306.54498 -205.19263)
		(end 306.117498 -205.620112)
		(width 0.18288)
		(layer "In2.Cu")
		(net "M_B_CPU0_SB_DQ<22>")
	)
	(segment
		(start 318.4398 -206.899764)
		(end 317.859664 -206.899764)
		(width 0.18288)
		(layer "In2.Cu")
		(net "M_B_CPU0_SB_DQ<22>")
	)
	(segment
		(start 303.564544 -206.577184)
		(end 303.29124 -206.577184)
		(width 0.18288)
		(layer "In2.Cu")
		(net "M_B_CPU0_SB_DQ<22>")
	)
	(segment
		(start 315.567568 -206.722726)
		(end 315.567568 -206.126588)
		(width 0.18288)
		(layer "In2.Cu")
		(net "M_B_CPU0_SB_DQ<22>")
	)
	(segment
		(start 302.068738 -206.409798)
		(end 300.598078 -206.409798)
		(width 0.18288)
		(layer "In2.Cu")
		(net "M_B_CPU0_SB_DQ<22>")
	)
	(segment
		(start 309.480204 -205.109826)
		(end 308.310788 -205.109826)
		(width 0.18288)
		(layer "In2.Cu")
		(net "M_B_CPU0_SB_DQ<22>")
	)
	(segment
		(start 300.598078 -206.409798)
		(end 300.389544 -206.201264)
		(width 0.18288)
		(layer "In2.Cu")
		(net "M_B_CPU0_SB_DQ<22>")
	)
	(segment
		(start 306.903882 -205.19263)
		(end 306.54498 -205.19263)
		(width 0.18288)
		(layer "In2.Cu")
		(net "M_B_CPU0_SB_DQ<22>")
	)
	(segment
		(start 303.849024 -206.292704)
		(end 303.564544 -206.577184)
		(width 0.18288)
		(layer "In2.Cu")
		(net "M_B_CPU0_SB_DQ<22>")
	)
	(segment
		(start 310.355234 -205.401164)
		(end 309.771542 -205.401164)
		(width 0.18288)
		(layer "In2.Cu")
		(net "M_B_CPU0_SB_DQ<22>")
	)
	(segment
		(start 304.83429 -205.620112)
		(end 304.551842 -205.337664)
		(width 0.18288)
		(layer "In2.Cu")
		(net "M_B_CPU0_SB_DQ<22>")
	)
	(segment
		(start 313.865768 -205.327504)
		(end 313.67603 -205.517242)
		(width 0.18288)
		(layer "In2.Cu")
		(net "M_B_CPU0_SB_DQ<22>")
	)
	(segment
		(start 307.236876 -205.525624)
		(end 306.903882 -205.19263)
		(width 0.18288)
		(layer "In2.Cu")
		(net "M_B_CPU0_SB_DQ<22>")
	)
	(segment
		(start 300.389544 -206.201264)
		(end 299.46981 -206.201264)
		(width 0.18288)
		(layer "In2.Cu")
		(net "M_B_CPU0_SB_DQ<22>")
	)
	(segment
		(start 337.227164 -226.33305)
		(end 337.212432 -226.341686)
		(width 0.088646)
		(layer "In2.Cu")
		(net "M_B_CPU0_SB_DQ<22>")
	)
	(segment
		(start 333.458566 -221.099634)
		(end 333.315818 -220.956886)
		(width 0.18288)
		(layer "In2.Cu")
		(net "M_B_CPU0_SB_DQ<22>")
	)
	(segment
		(start 303.29124 -206.577184)
		(end 302.757078 -206.043022)
		(width 0.18288)
		(layer "In2.Cu")
		(net "M_B_CPU0_SB_DQ<22>")
	)
	(segment
		(start 338.43468 -226.831144)
		(end 338.415376 -226.831144)
		(width 0.088646)
		(layer "In2.Cu")
		(net "M_B_CPU0_SB_DQ<22>")
	)
	(segment
		(start 313.67603 -205.517242)
		(end 312.22442 -205.517242)
		(width 0.18288)
		(layer "In2.Cu")
		(net "M_B_CPU0_SB_DQ<22>")
	)
	(segment
		(start 303.849024 -205.543658)
		(end 303.849024 -206.292704)
		(width 0.18288)
		(layer "In2.Cu")
		(net "M_B_CPU0_SB_DQ<22>")
	)
	(segment
		(start 302.757078 -206.043022)
		(end 302.435514 -206.043022)
		(width 0.18288)
		(layer "In2.Cu")
		(net "M_B_CPU0_SB_DQ<22>")
	)
	(arc
		(start 336.829146 -224.70872)
		(mid 336.698232 -224.57236)
		(end 336.650584 -224.389442)
		(width 0.088646)
		(layer "In2.Cu")
		(net "M_B_CPU0_SB_DQ<22>")
	)
	(arc
		(start 337.120484 -225.193352)
		(mid 337.042373 -224.916403)
		(end 336.838036 -224.7138)
		(width 0.088646)
		(layer "In2.Cu")
		(net "M_B_CPU0_SB_DQ<22>")
	)
	(arc
		(start 335.802732 -223.899984)
		(mid 335.615534 -223.950127)
		(end 335.428336 -223.899984)
		(width 0.088646)
		(layer "In2.Cu")
		(net "M_B_CPU0_SB_DQ<22>")
	)
	(arc
		(start 336.829146 -226.336606)
		(mid 336.650549 -226.017328)
		(end 336.829146 -225.69805)
		(width 0.088646)
		(layer "In2.Cu")
		(net "M_B_CPU0_SB_DQ<22>")
	)
	(arc
		(start 336.357468 -223.893888)
		(mid 336.07929 -223.824165)
		(end 335.802732 -223.899984)
		(width 0.088646)
		(layer "In2.Cu")
		(net "M_B_CPU0_SB_DQ<22>")
	)
	(arc
		(start 334.488536 -222.272098)
		(mid 334.447727 -222.244926)
		(end 334.410812 -222.212662)
		(width 0.088646)
		(layer "In2.Cu")
		(net "M_B_CPU0_SB_DQ<22>")
	)
	(arc
		(start 337.212432 -226.341686)
		(mid 337.025234 -226.391829)
		(end 336.838036 -226.341686)
		(width 0.088646)
		(layer "In2.Cu")
		(net "M_B_CPU0_SB_DQ<22>")
	)
	(arc
		(start 334.770984 -222.75165)
		(mid 334.692873 -222.474701)
		(end 334.488536 -222.272098)
		(width 0.088646)
		(layer "In2.Cu")
		(net "M_B_CPU0_SB_DQ<22>")
	)
	(arc
		(start 335.419446 -223.894904)
		(mid 335.288532 -223.758544)
		(end 335.240884 -223.575626)
		(width 0.088646)
		(layer "In2.Cu")
		(net "M_B_CPU0_SB_DQ<22>")
	)
	(arc
		(start 337.777836 -226.341686)
		(mid 337.503637 -226.265851)
		(end 337.227164 -226.33305)
		(width 0.088646)
		(layer "In2.Cu")
		(net "M_B_CPU0_SB_DQ<22>")
	)
	(arc
		(start 338.415376 -226.831144)
		(mid 338.112625 -226.565549)
		(end 337.777836 -226.341686)
		(width 0.088646)
		(layer "In2.Cu")
		(net "M_B_CPU0_SB_DQ<22>")
	)
	(arc
		(start 334.949546 -223.080834)
		(mid 334.818632 -222.944474)
		(end 334.770984 -222.761556)
		(width 0.088646)
		(layer "In2.Cu")
		(net "M_B_CPU0_SB_DQ<22>")
	)
	(arc
		(start 336.838036 -225.69297)
		(mid 337.040322 -225.493989)
		(end 337.120484 -225.2218)
		(width 0.088646)
		(layer "In2.Cu")
		(net "M_B_CPU0_SB_DQ<22>")
	)
	(arc
		(start 336.650584 -224.389442)
		(mid 336.576593 -224.109876)
		(end 336.373978 -223.90354)
		(width 0.088646)
		(layer "In2.Cu")
		(net "M_B_CPU0_SB_DQ<22>")
	)
	(arc
		(start 335.240884 -223.557084)
		(mid 335.160722 -223.284895)
		(end 334.958436 -223.085914)
		(width 0.088646)
		(layer "In2.Cu")
		(net "M_B_CPU0_SB_DQ<22>")
	)
	(segment
		(start 288.305748 -206.028036)
		(end 287.801304 -206.028036)
		(width 0.20066)
		(layer "F.Cu")
		(net "M_B_CPU0_SB_DQ<21>")
	)
	(segment
		(start 294.904414 -205.816708)
		(end 293.799514 -205.816708)
		(width 0.20066)
		(layer "F.Cu")
		(net "M_B_CPU0_SB_DQ<21>")
	)
	(segment
		(start 337.025234 -226.553014)
		(end 337.025234 -226.017328)
		(width 0.20066)
		(layer "F.Cu")
		(net "M_B_CPU0_SB_DQ<21>")
	)
	(segment
		(start 289.240468 -205.391766)
		(end 289.231578 -205.382876)
		(width 0.1016)
		(layer "F.Cu")
		(net "M_B_CPU0_SB_DQ<21>")
	)
	(segment
		(start 288.62274 -205.382876)
		(end 288.46018 -205.545436)
		(width 0.20066)
		(layer "F.Cu")
		(net "M_B_CPU0_SB_DQ<21>")
	)
	(segment
		(start 292.160198 -205.816708)
		(end 291.735256 -205.391766)
		(width 0.20066)
		(layer "F.Cu")
		(net "M_B_CPU0_SB_DQ<21>")
	)
	(segment
		(start 293.799514 -205.816708)
		(end 292.160198 -205.816708)
		(width 0.20066)
		(layer "F.Cu")
		(net "M_B_CPU0_SB_DQ<21>")
	)
	(segment
		(start 291.735256 -205.391766)
		(end 291.556694 -205.391766)
		(width 0.20066)
		(layer "F.Cu")
		(net "M_B_CPU0_SB_DQ<21>")
	)
	(segment
		(start 287.801304 -206.028036)
		(end 287.589976 -205.816708)
		(width 0.20066)
		(layer "F.Cu")
		(net "M_B_CPU0_SB_DQ<21>")
	)
	(segment
		(start 337.02498 -226.553268)
		(end 337.025234 -226.553014)
		(width 0.20066)
		(layer "F.Cu")
		(net "M_B_CPU0_SB_DQ<21>")
	)
	(segment
		(start 291.225986 -205.391766)
		(end 289.240468 -205.391766)
		(width 0.1016)
		(layer "F.Cu")
		(net "M_B_CPU0_SB_DQ<21>")
	)
	(segment
		(start 287.589976 -205.816708)
		(end 286.255714 -205.816708)
		(width 0.20066)
		(layer "F.Cu")
		(net "M_B_CPU0_SB_DQ<21>")
	)
	(segment
		(start 288.46018 -205.873604)
		(end 288.305748 -206.028036)
		(width 0.20066)
		(layer "F.Cu")
		(net "M_B_CPU0_SB_DQ<21>")
	)
	(segment
		(start 288.46018 -205.545436)
		(end 288.46018 -205.873604)
		(width 0.20066)
		(layer "F.Cu")
		(net "M_B_CPU0_SB_DQ<21>")
	)
	(segment
		(start 291.556694 -205.391766)
		(end 291.225986 -205.391766)
		(width 0.101854)
		(layer "F.Cu")
		(net "M_B_CPU0_SB_DQ<21>")
	)
	(segment
		(start 289.231578 -205.382876)
		(end 288.62274 -205.382876)
		(width 0.20066)
		(layer "F.Cu")
		(net "M_B_CPU0_SB_DQ<21>")
	)
	(segment
		(start 317.745618 -205.422246)
		(end 315.28639 -205.422246)
		(width 0.18288)
		(layer "In2.Cu")
		(net "M_B_CPU0_SB_DQ<21>")
	)
	(segment
		(start 302.237394 -205.47457)
		(end 301.916338 -205.153514)
		(width 0.18288)
		(layer "In2.Cu")
		(net "M_B_CPU0_SB_DQ<21>")
	)
	(segment
		(start 315.28639 -205.422246)
		(end 314.40755 -204.543406)
		(width 0.18288)
		(layer "In2.Cu")
		(net "M_B_CPU0_SB_DQ<21>")
	)
	(segment
		(start 311.992772 -204.67701)
		(end 310.453786 -204.67701)
		(width 0.18288)
		(layer "In2.Cu")
		(net "M_B_CPU0_SB_DQ<21>")
	)
	(segment
		(start 310.195214 -204.418438)
		(end 309.870348 -204.418438)
		(width 0.18288)
		(layer "In2.Cu")
		(net "M_B_CPU0_SB_DQ<21>")
	)
	(segment
		(start 337.399884 -224.404936)
		(end 337.399884 -224.389442)
		(width 0.088646)
		(layer "In2.Cu")
		(net "M_B_CPU0_SB_DQ<21>")
	)
	(segment
		(start 303.65065 -204.588872)
		(end 302.764952 -205.47457)
		(width 0.18288)
		(layer "In2.Cu")
		(net "M_B_CPU0_SB_DQ<21>")
	)
	(segment
		(start 309.870348 -204.418438)
		(end 309.770272 -204.518514)
		(width 0.18288)
		(layer "In2.Cu")
		(net "M_B_CPU0_SB_DQ<21>")
	)
	(segment
		(start 332.752446 -220.429074)
		(end 317.745618 -205.422246)
		(width 0.18288)
		(layer "In2.Cu")
		(net "M_B_CPU0_SB_DQ<21>")
	)
	(segment
		(start 302.764952 -205.47457)
		(end 302.237394 -205.47457)
		(width 0.18288)
		(layer "In2.Cu")
		(net "M_B_CPU0_SB_DQ<21>")
	)
	(segment
		(start 337.690968 -224.88398)
		(end 337.682078 -224.8789)
		(width 0.088646)
		(layer "In2.Cu")
		(net "M_B_CPU0_SB_DQ<21>")
	)
	(segment
		(start 337.337908 -226.017328)
		(end 337.403186 -225.95205)
		(width 0.088646)
		(layer "In2.Cu")
		(net "M_B_CPU0_SB_DQ<21>")
	)
	(segment
		(start 333.507842 -220.429074)
		(end 332.752446 -220.429074)
		(width 0.18288)
		(layer "In2.Cu")
		(net "M_B_CPU0_SB_DQ<21>")
	)
	(segment
		(start 314.40755 -204.543406)
		(end 313.915298 -204.543406)
		(width 0.18288)
		(layer "In2.Cu")
		(net "M_B_CPU0_SB_DQ<21>")
	)
	(segment
		(start 312.22823 -204.441552)
		(end 311.992772 -204.67701)
		(width 0.18288)
		(layer "In2.Cu")
		(net "M_B_CPU0_SB_DQ<21>")
	)
	(segment
		(start 306.121054 -204.367384)
		(end 304.778918 -204.367384)
		(width 0.18288)
		(layer "In2.Cu")
		(net "M_B_CPU0_SB_DQ<21>")
	)
	(segment
		(start 313.813444 -204.441552)
		(end 312.22823 -204.441552)
		(width 0.18288)
		(layer "In2.Cu")
		(net "M_B_CPU0_SB_DQ<21>")
	)
	(segment
		(start 301.916338 -205.153514)
		(end 300.727872 -205.153514)
		(width 0.18288)
		(layer "In2.Cu")
		(net "M_B_CPU0_SB_DQ<21>")
	)
	(segment
		(start 300.727872 -205.153514)
		(end 300.237906 -205.64348)
		(width 0.18288)
		(layer "In2.Cu")
		(net "M_B_CPU0_SB_DQ<21>")
	)
	(segment
		(start 336.751168 -223.256348)
		(end 336.742278 -223.251268)
		(width 0.088646)
		(layer "In2.Cu")
		(net "M_B_CPU0_SB_DQ<21>")
	)
	(segment
		(start 334.767936 -221.546928)
		(end 334.515968 -221.29496)
		(width 0.088646)
		(layer "In2.Cu")
		(net "M_B_CPU0_SB_DQ<21>")
	)
	(segment
		(start 333.818484 -220.739716)
		(end 333.507842 -220.429074)
		(width 0.18288)
		(layer "In2.Cu")
		(net "M_B_CPU0_SB_DQ<21>")
	)
	(segment
		(start 306.427886 -204.674216)
		(end 306.121054 -204.367384)
		(width 0.18288)
		(layer "In2.Cu")
		(net "M_B_CPU0_SB_DQ<21>")
	)
	(segment
		(start 309.770272 -204.518514)
		(end 306.946046 -204.518514)
		(width 0.18288)
		(layer "In2.Cu")
		(net "M_B_CPU0_SB_DQ<21>")
	)
	(segment
		(start 335.050384 -221.957646)
		(end 335.050384 -221.94774)
		(width 0.088646)
		(layer "In2.Cu")
		(net "M_B_CPU0_SB_DQ<21>")
	)
	(segment
		(start 337.221322 -224.070164)
		(end 337.212432 -224.065084)
		(width 0.088646)
		(layer "In2.Cu")
		(net "M_B_CPU0_SB_DQ<21>")
	)
	(segment
		(start 306.946046 -204.518514)
		(end 306.790344 -204.674216)
		(width 0.18288)
		(layer "In2.Cu")
		(net "M_B_CPU0_SB_DQ<21>")
	)
	(segment
		(start 310.453786 -204.67701)
		(end 310.195214 -204.418438)
		(width 0.18288)
		(layer "In2.Cu")
		(net "M_B_CPU0_SB_DQ<21>")
	)
	(segment
		(start 304.55743 -204.588872)
		(end 303.65065 -204.588872)
		(width 0.18288)
		(layer "In2.Cu")
		(net "M_B_CPU0_SB_DQ<21>")
	)
	(segment
		(start 337.682078 -225.527616)
		(end 337.690968 -225.522536)
		(width 0.088646)
		(layer "In2.Cu")
		(net "M_B_CPU0_SB_DQ<21>")
	)
	(segment
		(start 313.915298 -204.543406)
		(end 313.813444 -204.441552)
		(width 0.18288)
		(layer "In2.Cu")
		(net "M_B_CPU0_SB_DQ<21>")
	)
	(segment
		(start 334.515968 -221.29496)
		(end 334.373728 -221.29496)
		(width 0.088646)
		(layer "In2.Cu")
		(net "M_B_CPU0_SB_DQ<21>")
	)
	(segment
		(start 337.025234 -226.017328)
		(end 337.337908 -226.017328)
		(width 0.088646)
		(layer "In2.Cu")
		(net "M_B_CPU0_SB_DQ<21>")
	)
	(segment
		(start 297.100752 -205.391766)
		(end 296.911522 -205.202536)
		(width 0.18288)
		(layer "In2.Cu")
		(net "M_B_CPU0_SB_DQ<21>")
	)
	(segment
		(start 300.237906 -205.64348)
		(end 299.507656 -205.64348)
		(width 0.18288)
		(layer "In2.Cu")
		(net "M_B_CPU0_SB_DQ<21>")
	)
	(segment
		(start 304.778918 -204.367384)
		(end 304.55743 -204.588872)
		(width 0.18288)
		(layer "In2.Cu")
		(net "M_B_CPU0_SB_DQ<21>")
	)
	(segment
		(start 335.520284 -222.77578)
		(end 335.520284 -222.761556)
		(width 0.088646)
		(layer "In2.Cu")
		(net "M_B_CPU0_SB_DQ<21>")
	)
	(segment
		(start 299.255942 -205.391766)
		(end 297.100752 -205.391766)
		(width 0.18288)
		(layer "In2.Cu")
		(net "M_B_CPU0_SB_DQ<21>")
	)
	(segment
		(start 337.212432 -224.065084)
		(end 337.20024 -224.057972)
		(width 0.088646)
		(layer "In2.Cu")
		(net "M_B_CPU0_SB_DQ<21>")
	)
	(segment
		(start 299.507656 -205.64348)
		(end 299.255942 -205.391766)
		(width 0.18288)
		(layer "In2.Cu")
		(net "M_B_CPU0_SB_DQ<21>")
	)
	(segment
		(start 334.373728 -221.29496)
		(end 333.818484 -220.739716)
		(width 0.088646)
		(layer "In2.Cu")
		(net "M_B_CPU0_SB_DQ<21>")
	)
	(segment
		(start 296.911522 -205.202536)
		(end 295.518586 -205.202536)
		(width 0.18288)
		(layer "In2.Cu")
		(net "M_B_CPU0_SB_DQ<21>")
	)
	(segment
		(start 335.341722 -222.442278)
		(end 335.332832 -222.437198)
		(width 0.088646)
		(layer "In2.Cu")
		(net "M_B_CPU0_SB_DQ<21>")
	)
	(segment
		(start 336.376518 -223.246442)
		(end 336.368136 -223.251268)
		(width 0.088646)
		(layer "In2.Cu")
		(net "M_B_CPU0_SB_DQ<21>")
	)
	(segment
		(start 336.368136 -223.251268)
		(end 336.353404 -223.259904)
		(width 0.088646)
		(layer "In2.Cu")
		(net "M_B_CPU0_SB_DQ<21>")
	)
	(segment
		(start 295.518586 -205.202536)
		(end 294.904414 -205.816708)
		(width 0.18288)
		(layer "In2.Cu")
		(net "M_B_CPU0_SB_DQ<21>")
	)
	(segment
		(start 306.790344 -204.674216)
		(end 306.427886 -204.674216)
		(width 0.18288)
		(layer "In2.Cu")
		(net "M_B_CPU0_SB_DQ<21>")
	)
	(arc
		(start 334.863186 -221.623128)
		(mid 334.861031 -221.621851)
		(end 334.858868 -221.620588)
		(width 0.088646)
		(layer "In2.Cu")
		(net "M_B_CPU0_SB_DQ<21>")
	)
	(arc
		(start 336.353404 -223.259904)
		(mid 336.076963 -223.32707)
		(end 335.802732 -223.251268)
		(width 0.088646)
		(layer "In2.Cu")
		(net "M_B_CPU0_SB_DQ<21>")
	)
	(arc
		(start 337.403186 -225.95205)
		(mid 337.4923 -225.706753)
		(end 337.682078 -225.527616)
		(width 0.088646)
		(layer "In2.Cu")
		(net "M_B_CPU0_SB_DQ<21>")
	)
	(arc
		(start 335.520284 -222.761556)
		(mid 335.472605 -222.578656)
		(end 335.341722 -222.442278)
		(width 0.088646)
		(layer "In2.Cu")
		(net "M_B_CPU0_SB_DQ<21>")
	)
	(arc
		(start 337.690968 -225.522536)
		(mid 337.869565 -225.203258)
		(end 337.690968 -224.88398)
		(width 0.088646)
		(layer "In2.Cu")
		(net "M_B_CPU0_SB_DQ<21>")
	)
	(arc
		(start 337.682078 -224.8789)
		(mid 337.479255 -224.678669)
		(end 337.399884 -224.404936)
		(width 0.088646)
		(layer "In2.Cu")
		(net "M_B_CPU0_SB_DQ<21>")
	)
	(arc
		(start 335.802732 -223.251268)
		(mid 335.599427 -223.050402)
		(end 335.520284 -222.77578)
		(width 0.088646)
		(layer "In2.Cu")
		(net "M_B_CPU0_SB_DQ<21>")
	)
	(arc
		(start 336.742278 -223.251268)
		(mid 336.560027 -223.201157)
		(end 336.376518 -223.246442)
		(width 0.088646)
		(layer "In2.Cu")
		(net "M_B_CPU0_SB_DQ<21>")
	)
	(arc
		(start 335.050384 -221.94774)
		(mid 335.002705 -221.76484)
		(end 334.871822 -221.628462)
		(width 0.088646)
		(layer "In2.Cu")
		(net "M_B_CPU0_SB_DQ<21>")
	)
	(arc
		(start 337.20024 -224.057972)
		(mid 337.002012 -223.852124)
		(end 336.92973 -223.575626)
		(width 0.088646)
		(layer "In2.Cu")
		(net "M_B_CPU0_SB_DQ<21>")
	)
	(arc
		(start 334.871822 -221.628462)
		(mid 334.867492 -221.625815)
		(end 334.863186 -221.623128)
		(width 0.088646)
		(layer "In2.Cu")
		(net "M_B_CPU0_SB_DQ<21>")
	)
	(arc
		(start 335.332832 -222.437198)
		(mid 335.128497 -222.234593)
		(end 335.050384 -221.957646)
		(width 0.088646)
		(layer "In2.Cu")
		(net "M_B_CPU0_SB_DQ<21>")
	)
	(arc
		(start 337.399884 -224.389442)
		(mid 337.352205 -224.206542)
		(end 337.221322 -224.070164)
		(width 0.088646)
		(layer "In2.Cu")
		(net "M_B_CPU0_SB_DQ<21>")
	)
	(arc
		(start 336.92973 -223.575626)
		(mid 336.882051 -223.392726)
		(end 336.751168 -223.256348)
		(width 0.088646)
		(layer "In2.Cu")
		(net "M_B_CPU0_SB_DQ<21>")
	)
	(arc
		(start 334.858868 -221.620588)
		(mid 334.811494 -221.586113)
		(end 334.767936 -221.546928)
		(width 0.088646)
		(layer "In2.Cu")
		(net "M_B_CPU0_SB_DQ<21>")
	)
	(segment
		(start 287.828736 -207.75549)
		(end 287.589976 -207.51673)
		(width 0.20066)
		(layer "F.Cu")
		(net "M_B_CPU0_SB_DQ<20>")
	)
	(segment
		(start 288.66973 -207.08366)
		(end 288.46018 -207.29321)
		(width 0.20066)
		(layer "F.Cu")
		(net "M_B_CPU0_SB_DQ<20>")
	)
	(segment
		(start 292.430454 -207.51673)
		(end 292.005512 -207.091788)
		(width 0.20066)
		(layer "F.Cu")
		(net "M_B_CPU0_SB_DQ<20>")
	)
	(segment
		(start 291.556694 -207.091788)
		(end 289.48761 -207.091788)
		(width 0.1016)
		(layer "F.Cu")
		(net "M_B_CPU0_SB_DQ<20>")
	)
	(segment
		(start 336.555334 -227.367084)
		(end 336.555334 -226.831398)
		(width 0.20066)
		(layer "F.Cu")
		(net "M_B_CPU0_SB_DQ<20>")
	)
	(segment
		(start 288.28746 -207.75549)
		(end 287.828736 -207.75549)
		(width 0.20066)
		(layer "F.Cu")
		(net "M_B_CPU0_SB_DQ<20>")
	)
	(segment
		(start 293.799514 -207.51673)
		(end 292.430454 -207.51673)
		(width 0.20066)
		(layer "F.Cu")
		(net "M_B_CPU0_SB_DQ<20>")
	)
	(segment
		(start 289.231578 -207.08366)
		(end 288.66973 -207.08366)
		(width 0.20066)
		(layer "F.Cu")
		(net "M_B_CPU0_SB_DQ<20>")
	)
	(segment
		(start 294.904414 -207.51673)
		(end 293.799514 -207.51673)
		(width 0.20066)
		(layer "F.Cu")
		(net "M_B_CPU0_SB_DQ<20>")
	)
	(segment
		(start 288.46018 -207.29321)
		(end 288.46018 -207.58277)
		(width 0.20066)
		(layer "F.Cu")
		(net "M_B_CPU0_SB_DQ<20>")
	)
	(segment
		(start 288.46018 -207.58277)
		(end 288.28746 -207.75549)
		(width 0.20066)
		(layer "F.Cu")
		(net "M_B_CPU0_SB_DQ<20>")
	)
	(segment
		(start 287.589976 -207.51673)
		(end 286.255714 -207.51673)
		(width 0.20066)
		(layer "F.Cu")
		(net "M_B_CPU0_SB_DQ<20>")
	)
	(segment
		(start 336.555334 -226.831398)
		(end 336.55508 -226.831144)
		(width 0.20066)
		(layer "F.Cu")
		(net "M_B_CPU0_SB_DQ<20>")
	)
	(segment
		(start 289.48761 -207.091788)
		(end 289.239706 -207.091788)
		(width 0.101854)
		(layer "F.Cu")
		(net "M_B_CPU0_SB_DQ<20>")
	)
	(segment
		(start 289.239706 -207.091788)
		(end 289.231578 -207.08366)
		(width 0.101854)
		(layer "F.Cu")
		(net "M_B_CPU0_SB_DQ<20>")
	)
	(segment
		(start 292.005512 -207.091788)
		(end 291.556694 -207.091788)
		(width 0.20066)
		(layer "F.Cu")
		(net "M_B_CPU0_SB_DQ<20>")
	)
	(segment
		(start 310.865266 -206.88681)
		(end 310.865266 -206.145384)
		(width 0.18288)
		(layer "In2.Cu")
		(net "M_B_CPU0_SB_DQ<20>")
	)
	(segment
		(start 297.038776 -207.091534)
		(end 296.84345 -206.896208)
		(width 0.18288)
		(layer "In2.Cu")
		(net "M_B_CPU0_SB_DQ<20>")
	)
	(segment
		(start 306.21478 -206.242412)
		(end 304.626518 -206.242412)
		(width 0.18288)
		(layer "In2.Cu")
		(net "M_B_CPU0_SB_DQ<20>")
	)
	(segment
		(start 311.650126 -206.91475)
		(end 311.485026 -207.07985)
		(width 0.18288)
		(layer "In2.Cu")
		(net "M_B_CPU0_SB_DQ<20>")
	)
	(segment
		(start 336.460084 -224.399348)
		(end 336.460084 -224.389442)
		(width 0.088646)
		(layer "In2.Cu")
		(net "M_B_CPU0_SB_DQ<20>")
	)
	(segment
		(start 306.28717 -206.314802)
		(end 306.21478 -206.242412)
		(width 0.18288)
		(layer "In2.Cu")
		(net "M_B_CPU0_SB_DQ<20>")
	)
	(segment
		(start 336.55508 -226.831144)
		(end 336.517742 -226.266502)
		(width 0.088646)
		(layer "In2.Cu")
		(net "M_B_CPU0_SB_DQ<20>")
	)
	(segment
		(start 309.968392 -205.95209)
		(end 309.722012 -206.19847)
		(width 0.18288)
		(layer "In2.Cu")
		(net "M_B_CPU0_SB_DQ<20>")
	)
	(segment
		(start 296.84345 -206.896208)
		(end 295.524936 -206.896208)
		(width 0.18288)
		(layer "In2.Cu")
		(net "M_B_CPU0_SB_DQ<20>")
	)
	(segment
		(start 299.618908 -207.307434)
		(end 299.403008 -207.091534)
		(width 0.18288)
		(layer "In2.Cu")
		(net "M_B_CPU0_SB_DQ<20>")
	)
	(segment
		(start 310.865266 -206.145384)
		(end 310.671972 -205.95209)
		(width 0.18288)
		(layer "In2.Cu")
		(net "M_B_CPU0_SB_DQ<20>")
	)
	(segment
		(start 309.722012 -206.19847)
		(end 308.005734 -206.19847)
		(width 0.18288)
		(layer "In2.Cu")
		(net "M_B_CPU0_SB_DQ<20>")
	)
	(segment
		(start 336.92973 -225.211894)
		(end 336.92973 -225.194622)
		(width 0.088646)
		(layer "In2.Cu")
		(net "M_B_CPU0_SB_DQ<20>")
	)
	(segment
		(start 302.237394 -207.109314)
		(end 302.068484 -206.940404)
		(width 0.18288)
		(layer "In2.Cu")
		(net "M_B_CPU0_SB_DQ<20>")
	)
	(segment
		(start 300.251114 -207.307434)
		(end 299.618908 -207.307434)
		(width 0.18288)
		(layer "In2.Cu")
		(net "M_B_CPU0_SB_DQ<20>")
	)
	(segment
		(start 310.671972 -205.95209)
		(end 309.968392 -205.95209)
		(width 0.18288)
		(layer "In2.Cu")
		(net "M_B_CPU0_SB_DQ<20>")
	)
	(segment
		(start 311.485026 -207.07985)
		(end 311.058306 -207.07985)
		(width 0.18288)
		(layer "In2.Cu")
		(net "M_B_CPU0_SB_DQ<20>")
	)
	(segment
		(start 308.005734 -206.19847)
		(end 307.857398 -206.050134)
		(width 0.18288)
		(layer "In2.Cu")
		(net "M_B_CPU0_SB_DQ<20>")
	)
	(segment
		(start 307.857398 -206.050134)
		(end 307.168296 -206.050134)
		(width 0.18288)
		(layer "In2.Cu")
		(net "M_B_CPU0_SB_DQ<20>")
	)
	(segment
		(start 333.15402 -221.506796)
		(end 332.297024 -221.506796)
		(width 0.18288)
		(layer "In2.Cu")
		(net "M_B_CPU0_SB_DQ<20>")
	)
	(segment
		(start 335.050384 -223.585532)
		(end 335.050384 -223.575626)
		(width 0.088646)
		(layer "In2.Cu")
		(net "M_B_CPU0_SB_DQ<20>")
	)
	(segment
		(start 295.524936 -206.896208)
		(end 294.904414 -207.51673)
		(width 0.18288)
		(layer "In2.Cu")
		(net "M_B_CPU0_SB_DQ<20>")
	)
	(segment
		(start 311.058306 -207.07985)
		(end 310.865266 -206.88681)
		(width 0.18288)
		(layer "In2.Cu")
		(net "M_B_CPU0_SB_DQ<20>")
	)
	(segment
		(start 333.435198 -221.506796)
		(end 333.15402 -221.506796)
		(width 0.088646)
		(layer "In2.Cu")
		(net "M_B_CPU0_SB_DQ<20>")
	)
	(segment
		(start 306.903628 -206.314802)
		(end 306.28717 -206.314802)
		(width 0.18288)
		(layer "In2.Cu")
		(net "M_B_CPU0_SB_DQ<20>")
	)
	(segment
		(start 299.403008 -207.091534)
		(end 297.038776 -207.091534)
		(width 0.18288)
		(layer "In2.Cu")
		(net "M_B_CPU0_SB_DQ<20>")
	)
	(segment
		(start 336.281522 -224.070164)
		(end 336.272632 -224.065084)
		(width 0.088646)
		(layer "In2.Cu")
		(net "M_B_CPU0_SB_DQ<20>")
	)
	(segment
		(start 334.275938 -222.347536)
		(end 333.435198 -221.506796)
		(width 0.088646)
		(layer "In2.Cu")
		(net "M_B_CPU0_SB_DQ<20>")
	)
	(segment
		(start 311.650126 -206.661004)
		(end 311.650126 -206.91475)
		(width 0.18288)
		(layer "In2.Cu")
		(net "M_B_CPU0_SB_DQ<20>")
	)
	(segment
		(start 304.626518 -206.242412)
		(end 303.759616 -207.109314)
		(width 0.18288)
		(layer "In2.Cu")
		(net "M_B_CPU0_SB_DQ<20>")
	)
	(segment
		(start 334.580484 -222.780098)
		(end 334.580484 -222.761556)
		(width 0.088646)
		(layer "In2.Cu")
		(net "M_B_CPU0_SB_DQ<20>")
	)
	(segment
		(start 318.213994 -207.423766)
		(end 315.047122 -207.423766)
		(width 0.18288)
		(layer "In2.Cu")
		(net "M_B_CPU0_SB_DQ<20>")
	)
	(segment
		(start 336.460084 -226.032822)
		(end 336.460084 -225.998786)
		(width 0.088646)
		(layer "In2.Cu")
		(net "M_B_CPU0_SB_DQ<20>")
	)
	(segment
		(start 313.842908 -206.219552)
		(end 312.091578 -206.219552)
		(width 0.18288)
		(layer "In2.Cu")
		(net "M_B_CPU0_SB_DQ<20>")
	)
	(segment
		(start 303.759616 -207.109314)
		(end 302.237394 -207.109314)
		(width 0.18288)
		(layer "In2.Cu")
		(net "M_B_CPU0_SB_DQ<20>")
	)
	(segment
		(start 307.168296 -206.050134)
		(end 306.903628 -206.314802)
		(width 0.18288)
		(layer "In2.Cu")
		(net "M_B_CPU0_SB_DQ<20>")
	)
	(segment
		(start 332.297024 -221.506796)
		(end 318.213994 -207.423766)
		(width 0.18288)
		(layer "In2.Cu")
		(net "M_B_CPU0_SB_DQ<20>")
	)
	(segment
		(start 300.618144 -206.940404)
		(end 300.251114 -207.307434)
		(width 0.18288)
		(layer "In2.Cu")
		(net "M_B_CPU0_SB_DQ<20>")
	)
	(segment
		(start 302.068484 -206.940404)
		(end 300.618144 -206.940404)
		(width 0.18288)
		(layer "In2.Cu")
		(net "M_B_CPU0_SB_DQ<20>")
	)
	(segment
		(start 334.871822 -223.256348)
		(end 334.862932 -223.251268)
		(width 0.088646)
		(layer "In2.Cu")
		(net "M_B_CPU0_SB_DQ<20>")
	)
	(segment
		(start 312.091578 -206.219552)
		(end 311.650126 -206.661004)
		(width 0.18288)
		(layer "In2.Cu")
		(net "M_B_CPU0_SB_DQ<20>")
	)
	(segment
		(start 315.047122 -207.423766)
		(end 313.842908 -206.219552)
		(width 0.18288)
		(layer "In2.Cu")
		(net "M_B_CPU0_SB_DQ<20>")
	)
	(arc
		(start 335.050384 -223.575626)
		(mid 335.002705 -223.392726)
		(end 334.871822 -223.256348)
		(width 0.088646)
		(layer "In2.Cu")
		(net "M_B_CPU0_SB_DQ<20>")
	)
	(arc
		(start 336.517742 -226.266502)
		(mid 336.476333 -226.152766)
		(end 336.460084 -226.032822)
		(width 0.088646)
		(layer "In2.Cu")
		(net "M_B_CPU0_SB_DQ<20>")
	)
	(arc
		(start 336.92973 -225.194622)
		(mid 336.87746 -225.012257)
		(end 336.742532 -224.8789)
		(width 0.088646)
		(layer "In2.Cu")
		(net "M_B_CPU0_SB_DQ<20>")
	)
	(arc
		(start 335.332832 -224.065084)
		(mid 335.128497 -223.862479)
		(end 335.050384 -223.585532)
		(width 0.088646)
		(layer "In2.Cu")
		(net "M_B_CPU0_SB_DQ<20>")
	)
	(arc
		(start 336.742532 -224.8789)
		(mid 336.538197 -224.676295)
		(end 336.460084 -224.399348)
		(width 0.088646)
		(layer "In2.Cu")
		(net "M_B_CPU0_SB_DQ<20>")
	)
	(arc
		(start 336.460084 -224.389442)
		(mid 336.412405 -224.206542)
		(end 336.281522 -224.070164)
		(width 0.088646)
		(layer "In2.Cu")
		(net "M_B_CPU0_SB_DQ<20>")
	)
	(arc
		(start 334.580484 -222.761556)
		(mid 334.532805 -222.578656)
		(end 334.401922 -222.442278)
		(width 0.088646)
		(layer "In2.Cu")
		(net "M_B_CPU0_SB_DQ<20>")
	)
	(arc
		(start 334.401922 -222.442278)
		(mid 334.335618 -222.399312)
		(end 334.275938 -222.347536)
		(width 0.088646)
		(layer "In2.Cu")
		(net "M_B_CPU0_SB_DQ<20>")
	)
	(arc
		(start 335.898236 -224.065084)
		(mid 335.615534 -224.14086)
		(end 335.332832 -224.065084)
		(width 0.088646)
		(layer "In2.Cu")
		(net "M_B_CPU0_SB_DQ<20>")
	)
	(arc
		(start 336.272632 -224.065084)
		(mid 336.085434 -224.014941)
		(end 335.898236 -224.065084)
		(width 0.088646)
		(layer "In2.Cu")
		(net "M_B_CPU0_SB_DQ<20>")
	)
	(arc
		(start 334.862932 -223.251268)
		(mid 334.660646 -223.052287)
		(end 334.580484 -222.780098)
		(width 0.088646)
		(layer "In2.Cu")
		(net "M_B_CPU0_SB_DQ<20>")
	)
	(arc
		(start 336.742532 -225.527616)
		(mid 336.877465 -225.394262)
		(end 336.92973 -225.211894)
		(width 0.088646)
		(layer "In2.Cu")
		(net "M_B_CPU0_SB_DQ<20>")
	)
	(arc
		(start 336.460084 -225.998786)
		(mid 336.540246 -225.726597)
		(end 336.742532 -225.527616)
		(width 0.088646)
		(layer "In2.Cu")
		(net "M_B_CPU0_SB_DQ<20>")
	)
	(segment
		(start 287.589976 -230.466646)
		(end 286.255714 -230.466646)
		(width 0.20066)
		(layer "F.Cu")
		(net "M_B_CPU0_SB_DQ<1>")
	)
	(segment
		(start 288.62274 -230.032814)
		(end 288.46018 -230.195374)
		(width 0.20066)
		(layer "F.Cu")
		(net "M_B_CPU0_SB_DQ<1>")
	)
	(segment
		(start 294.904414 -230.466646)
		(end 293.799514 -230.466646)
		(width 0.20066)
		(layer "F.Cu")
		(net "M_B_CPU0_SB_DQ<1>")
	)
	(segment
		(start 289.231578 -230.032814)
		(end 288.62274 -230.032814)
		(width 0.20066)
		(layer "F.Cu")
		(net "M_B_CPU0_SB_DQ<1>")
	)
	(segment
		(start 339.84438 -236.319822)
		(end 339.844634 -236.319568)
		(width 0.20066)
		(layer "F.Cu")
		(net "M_B_CPU0_SB_DQ<1>")
	)
	(segment
		(start 288.46018 -230.195374)
		(end 288.46018 -230.523542)
		(width 0.20066)
		(layer "F.Cu")
		(net "M_B_CPU0_SB_DQ<1>")
	)
	(segment
		(start 339.844634 -236.319568)
		(end 339.844634 -235.783882)
		(width 0.20066)
		(layer "F.Cu")
		(net "M_B_CPU0_SB_DQ<1>")
	)
	(segment
		(start 291.735256 -230.041704)
		(end 291.556694 -230.041704)
		(width 0.20066)
		(layer "F.Cu")
		(net "M_B_CPU0_SB_DQ<1>")
	)
	(segment
		(start 288.46018 -230.523542)
		(end 288.305748 -230.677974)
		(width 0.20066)
		(layer "F.Cu")
		(net "M_B_CPU0_SB_DQ<1>")
	)
	(segment
		(start 291.225986 -230.041704)
		(end 289.240468 -230.041704)
		(width 0.1016)
		(layer "F.Cu")
		(net "M_B_CPU0_SB_DQ<1>")
	)
	(segment
		(start 293.799514 -230.466646)
		(end 292.160198 -230.466646)
		(width 0.20066)
		(layer "F.Cu")
		(net "M_B_CPU0_SB_DQ<1>")
	)
	(segment
		(start 288.305748 -230.677974)
		(end 287.801304 -230.677974)
		(width 0.20066)
		(layer "F.Cu")
		(net "M_B_CPU0_SB_DQ<1>")
	)
	(segment
		(start 291.556694 -230.041704)
		(end 291.225986 -230.041704)
		(width 0.101854)
		(layer "F.Cu")
		(net "M_B_CPU0_SB_DQ<1>")
	)
	(segment
		(start 292.160198 -230.466646)
		(end 291.735256 -230.041704)
		(width 0.20066)
		(layer "F.Cu")
		(net "M_B_CPU0_SB_DQ<1>")
	)
	(segment
		(start 287.801304 -230.677974)
		(end 287.589976 -230.466646)
		(width 0.20066)
		(layer "F.Cu")
		(net "M_B_CPU0_SB_DQ<1>")
	)
	(segment
		(start 289.240468 -230.041704)
		(end 289.231578 -230.032814)
		(width 0.1016)
		(layer "F.Cu")
		(net "M_B_CPU0_SB_DQ<1>")
	)
	(segment
		(start 309.334916 -230.041704)
		(end 308.485032 -229.19182)
		(width 0.18288)
		(layer "In4.Cu")
		(net "M_B_CPU0_SB_DQ<1>")
	)
	(segment
		(start 332.844394 -236.273594)
		(end 332.680818 -236.341412)
		(width 0.088646)
		(layer "In4.Cu")
		(net "M_B_CPU0_SB_DQ<1>")
	)
	(segment
		(start 302.884586 -229.179374)
		(end 302.171862 -229.179374)
		(width 0.18288)
		(layer "In4.Cu")
		(net "M_B_CPU0_SB_DQ<1>")
	)
	(segment
		(start 297.863006 -229.858824)
		(end 297.863006 -229.468172)
		(width 0.18288)
		(layer "In4.Cu")
		(net "M_B_CPU0_SB_DQ<1>")
	)
	(segment
		(start 315.858398 -230.891842)
		(end 313.240166 -230.891842)
		(width 0.18288)
		(layer "In4.Cu")
		(net "M_B_CPU0_SB_DQ<1>")
	)
	(segment
		(start 295.790366 -229.242366)
		(end 295.790366 -229.858824)
		(width 0.18288)
		(layer "In4.Cu")
		(net "M_B_CPU0_SB_DQ<1>")
	)
	(segment
		(start 303.618392 -229.91318)
		(end 302.884586 -229.179374)
		(width 0.18288)
		(layer "In4.Cu")
		(net "M_B_CPU0_SB_DQ<1>")
	)
	(segment
		(start 302.171862 -229.179374)
		(end 301.515018 -229.836218)
		(width 0.18288)
		(layer "In4.Cu")
		(net "M_B_CPU0_SB_DQ<1>")
	)
	(segment
		(start 295.329356 -230.041704)
		(end 294.904414 -230.466646)
		(width 0.18288)
		(layer "In4.Cu")
		(net "M_B_CPU0_SB_DQ<1>")
	)
	(segment
		(start 298.045886 -230.041704)
		(end 297.863006 -229.858824)
		(width 0.18288)
		(layer "In4.Cu")
		(net "M_B_CPU0_SB_DQ<1>")
	)
	(segment
		(start 296.298366 -229.05085)
		(end 295.981882 -229.05085)
		(width 0.18288)
		(layer "In4.Cu")
		(net "M_B_CPU0_SB_DQ<1>")
	)
	(segment
		(start 305.578256 -229.19182)
		(end 304.856896 -229.91318)
		(width 0.18288)
		(layer "In4.Cu")
		(net "M_B_CPU0_SB_DQ<1>")
	)
	(segment
		(start 313.240166 -230.891842)
		(end 312.390028 -230.041704)
		(width 0.18288)
		(layer "In4.Cu")
		(net "M_B_CPU0_SB_DQ<1>")
	)
	(segment
		(start 296.481246 -229.23373)
		(end 296.298366 -229.05085)
		(width 0.18288)
		(layer "In4.Cu")
		(net "M_B_CPU0_SB_DQ<1>")
	)
	(segment
		(start 297.863006 -229.468172)
		(end 297.680126 -229.285292)
		(width 0.18288)
		(layer "In4.Cu")
		(net "M_B_CPU0_SB_DQ<1>")
	)
	(segment
		(start 297.172126 -229.858824)
		(end 296.989246 -230.041704)
		(width 0.18288)
		(layer "In4.Cu")
		(net "M_B_CPU0_SB_DQ<1>")
	)
	(segment
		(start 295.981882 -229.05085)
		(end 295.790366 -229.242366)
		(width 0.18288)
		(layer "In4.Cu")
		(net "M_B_CPU0_SB_DQ<1>")
	)
	(segment
		(start 336.367882 -236.27334)
		(end 336.368136 -236.273594)
		(width 0.088646)
		(layer "In4.Cu")
		(net "M_B_CPU0_SB_DQ<1>")
	)
	(segment
		(start 297.355006 -229.285292)
		(end 297.172126 -229.468172)
		(width 0.18288)
		(layer "In4.Cu")
		(net "M_B_CPU0_SB_DQ<1>")
	)
	(segment
		(start 337.689698 -236.277658)
		(end 337.67776 -236.2708)
		(width 0.088646)
		(layer "In4.Cu")
		(net "M_B_CPU0_SB_DQ<1>")
	)
	(segment
		(start 321.502786 -236.53623)
		(end 315.858398 -230.891842)
		(width 0.18288)
		(layer "In4.Cu")
		(net "M_B_CPU0_SB_DQ<1>")
	)
	(segment
		(start 297.680126 -229.285292)
		(end 297.355006 -229.285292)
		(width 0.18288)
		(layer "In4.Cu")
		(net "M_B_CPU0_SB_DQ<1>")
	)
	(segment
		(start 301.515018 -229.836218)
		(end 300.858174 -229.836218)
		(width 0.18288)
		(layer "In4.Cu")
		(net "M_B_CPU0_SB_DQ<1>")
	)
	(segment
		(start 297.172126 -229.468172)
		(end 297.172126 -229.858824)
		(width 0.18288)
		(layer "In4.Cu")
		(net "M_B_CPU0_SB_DQ<1>")
	)
	(segment
		(start 296.989246 -230.041704)
		(end 296.664126 -230.041704)
		(width 0.18288)
		(layer "In4.Cu")
		(net "M_B_CPU0_SB_DQ<1>")
	)
	(segment
		(start 336.742532 -236.27334)
		(end 336.738722 -236.271308)
		(width 0.088646)
		(layer "In4.Cu")
		(net "M_B_CPU0_SB_DQ<1>")
	)
	(segment
		(start 296.664126 -230.041704)
		(end 296.481246 -229.858824)
		(width 0.18288)
		(layer "In4.Cu")
		(net "M_B_CPU0_SB_DQ<1>")
	)
	(segment
		(start 332.486 -236.53623)
		(end 331.004164 -236.53623)
		(width 0.088646)
		(layer "In4.Cu")
		(net "M_B_CPU0_SB_DQ<1>")
	)
	(segment
		(start 296.481246 -229.858824)
		(end 296.481246 -229.23373)
		(width 0.18288)
		(layer "In4.Cu")
		(net "M_B_CPU0_SB_DQ<1>")
	)
	(segment
		(start 339.260688 -236.231176)
		(end 339.187282 -236.27334)
		(width 0.088646)
		(layer "In4.Cu")
		(net "M_B_CPU0_SB_DQ<1>")
	)
	(segment
		(start 304.856896 -229.91318)
		(end 303.618392 -229.91318)
		(width 0.18288)
		(layer "In4.Cu")
		(net "M_B_CPU0_SB_DQ<1>")
	)
	(segment
		(start 332.680818 -236.341412)
		(end 332.486 -236.53623)
		(width 0.088646)
		(layer "In4.Cu")
		(net "M_B_CPU0_SB_DQ<1>")
	)
	(segment
		(start 300.858174 -229.836218)
		(end 300.652688 -230.041704)
		(width 0.18288)
		(layer "In4.Cu")
		(net "M_B_CPU0_SB_DQ<1>")
	)
	(segment
		(start 295.607486 -230.041704)
		(end 295.329356 -230.041704)
		(width 0.18288)
		(layer "In4.Cu")
		(net "M_B_CPU0_SB_DQ<1>")
	)
	(segment
		(start 336.749898 -236.277658)
		(end 336.742532 -236.27334)
		(width 0.088646)
		(layer "In4.Cu")
		(net "M_B_CPU0_SB_DQ<1>")
	)
	(segment
		(start 338.622132 -236.27334)
		(end 338.61756 -236.2708)
		(width 0.088646)
		(layer "In4.Cu")
		(net "M_B_CPU0_SB_DQ<1>")
	)
	(segment
		(start 332.983332 -236.273594)
		(end 332.844394 -236.273594)
		(width 0.088646)
		(layer "In4.Cu")
		(net "M_B_CPU0_SB_DQ<1>")
	)
	(segment
		(start 300.652688 -230.041704)
		(end 298.045886 -230.041704)
		(width 0.18288)
		(layer "In4.Cu")
		(net "M_B_CPU0_SB_DQ<1>")
	)
	(segment
		(start 308.485032 -229.19182)
		(end 305.578256 -229.19182)
		(width 0.18288)
		(layer "In4.Cu")
		(net "M_B_CPU0_SB_DQ<1>")
	)
	(segment
		(start 295.790366 -229.858824)
		(end 295.607486 -230.041704)
		(width 0.18288)
		(layer "In4.Cu")
		(net "M_B_CPU0_SB_DQ<1>")
	)
	(segment
		(start 331.004164 -236.53623)
		(end 321.502786 -236.53623)
		(width 0.18288)
		(layer "In4.Cu")
		(net "M_B_CPU0_SB_DQ<1>")
	)
	(segment
		(start 338.629498 -236.277658)
		(end 338.622132 -236.27334)
		(width 0.088646)
		(layer "In4.Cu")
		(net "M_B_CPU0_SB_DQ<1>")
	)
	(segment
		(start 312.390028 -230.041704)
		(end 309.334916 -230.041704)
		(width 0.18288)
		(layer "In4.Cu")
		(net "M_B_CPU0_SB_DQ<1>")
	)
	(arc
		(start 337.307682 -236.27334)
		(mid 337.029359 -236.349099)
		(end 336.749898 -236.277658)
		(width 0.088646)
		(layer "In4.Cu")
		(net "M_B_CPU0_SB_DQ<1>")
	)
	(arc
		(start 337.67776 -236.2708)
		(mid 337.492375 -236.223162)
		(end 337.307682 -236.27334)
		(width 0.088646)
		(layer "In4.Cu")
		(net "M_B_CPU0_SB_DQ<1>")
	)
	(arc
		(start 338.61756 -236.2708)
		(mid 338.432175 -236.223162)
		(end 338.247482 -236.27334)
		(width 0.088646)
		(layer "In4.Cu")
		(net "M_B_CPU0_SB_DQ<1>")
	)
	(arc
		(start 333.923132 -236.273594)
		(mid 333.735934 -236.223451)
		(end 333.548736 -236.273594)
		(width 0.088646)
		(layer "In4.Cu")
		(net "M_B_CPU0_SB_DQ<1>")
	)
	(arc
		(start 334.862932 -236.273594)
		(mid 334.675734 -236.223451)
		(end 334.488536 -236.273594)
		(width 0.088646)
		(layer "In4.Cu")
		(net "M_B_CPU0_SB_DQ<1>")
	)
	(arc
		(start 333.548736 -236.273594)
		(mid 333.266034 -236.349336)
		(end 332.983332 -236.273594)
		(width 0.088646)
		(layer "In4.Cu")
		(net "M_B_CPU0_SB_DQ<1>")
	)
	(arc
		(start 336.368136 -236.273594)
		(mid 336.085434 -236.349336)
		(end 335.802732 -236.273594)
		(width 0.088646)
		(layer "In4.Cu")
		(net "M_B_CPU0_SB_DQ<1>")
	)
	(arc
		(start 338.247482 -236.27334)
		(mid 337.969159 -236.349099)
		(end 337.689698 -236.277658)
		(width 0.088646)
		(layer "In4.Cu")
		(net "M_B_CPU0_SB_DQ<1>")
	)
	(arc
		(start 335.802732 -236.273594)
		(mid 335.615534 -236.223451)
		(end 335.428336 -236.273594)
		(width 0.088646)
		(layer "In4.Cu")
		(net "M_B_CPU0_SB_DQ<1>")
	)
	(arc
		(start 334.488536 -236.273594)
		(mid 334.205834 -236.349336)
		(end 333.923132 -236.273594)
		(width 0.088646)
		(layer "In4.Cu")
		(net "M_B_CPU0_SB_DQ<1>")
	)
	(arc
		(start 339.844634 -235.783882)
		(mid 339.567454 -236.026843)
		(end 339.260688 -236.231176)
		(width 0.088646)
		(layer "In4.Cu")
		(net "M_B_CPU0_SB_DQ<1>")
	)
	(arc
		(start 335.428336 -236.273594)
		(mid 335.145634 -236.349336)
		(end 334.862932 -236.273594)
		(width 0.088646)
		(layer "In4.Cu")
		(net "M_B_CPU0_SB_DQ<1>")
	)
	(arc
		(start 339.187282 -236.27334)
		(mid 338.908959 -236.349099)
		(end 338.629498 -236.277658)
		(width 0.088646)
		(layer "In4.Cu")
		(net "M_B_CPU0_SB_DQ<1>")
	)
	(arc
		(start 336.738722 -236.271308)
		(mid 336.553032 -236.22323)
		(end 336.367882 -236.27334)
		(width 0.088646)
		(layer "In4.Cu")
		(net "M_B_CPU0_SB_DQ<1>")
	)
	(segment
		(start 338.434934 -228.99497)
		(end 338.434934 -228.459284)
		(width 0.20066)
		(layer "F.Cu")
		(net "M_B_CPU0_SB_DQ<19>")
	)
	(segment
		(start 292.05301 -210.916774)
		(end 290.355782 -210.916774)
		(width 0.20066)
		(layer "F.Cu")
		(net "M_B_CPU0_SB_DQ<19>")
	)
	(segment
		(start 292.178994 -211.213446)
		(end 292.178994 -211.042758)
		(width 0.20066)
		(layer "F.Cu")
		(net "M_B_CPU0_SB_DQ<19>")
	)
	(segment
		(start 295.82237 -210.912456)
		(end 295.693846 -211.04098)
		(width 0.20066)
		(layer "F.Cu")
		(net "M_B_CPU0_SB_DQ<19>")
	)
	(segment
		(start 299.004482 -210.916774)
		(end 297.899582 -210.916774)
		(width 0.20066)
		(layer "F.Cu")
		(net "M_B_CPU0_SB_DQ<19>")
	)
	(segment
		(start 296.875962 -211.124292)
		(end 296.42943 -211.124292)
		(width 0.20066)
		(layer "F.Cu")
		(net "M_B_CPU0_SB_DQ<19>")
	)
	(segment
		(start 297.899582 -210.916774)
		(end 297.08348 -210.916774)
		(width 0.20066)
		(layer "F.Cu")
		(net "M_B_CPU0_SB_DQ<19>")
	)
	(segment
		(start 292.67531 -211.35594)
		(end 292.321488 -211.35594)
		(width 0.20066)
		(layer "F.Cu")
		(net "M_B_CPU0_SB_DQ<19>")
	)
	(segment
		(start 297.08348 -210.916774)
		(end 296.875962 -211.124292)
		(width 0.20066)
		(layer "F.Cu")
		(net "M_B_CPU0_SB_DQ<19>")
	)
	(segment
		(start 295.000426 -211.341716)
		(end 292.927532 -211.341716)
		(width 0.1016)
		(layer "F.Cu")
		(net "M_B_CPU0_SB_DQ<19>")
	)
	(segment
		(start 295.544748 -211.341716)
		(end 295.000426 -211.341716)
		(width 0.20066)
		(layer "F.Cu")
		(net "M_B_CPU0_SB_DQ<19>")
	)
	(segment
		(start 295.693846 -211.04098)
		(end 295.693846 -211.192618)
		(width 0.20066)
		(layer "F.Cu")
		(net "M_B_CPU0_SB_DQ<19>")
	)
	(segment
		(start 296.42943 -211.124292)
		(end 296.217594 -210.912456)
		(width 0.20066)
		(layer "F.Cu")
		(net "M_B_CPU0_SB_DQ<19>")
	)
	(segment
		(start 292.178994 -211.042758)
		(end 292.05301 -210.916774)
		(width 0.20066)
		(layer "F.Cu")
		(net "M_B_CPU0_SB_DQ<19>")
	)
	(segment
		(start 292.927532 -211.341716)
		(end 292.689534 -211.341716)
		(width 0.101854)
		(layer "F.Cu")
		(net "M_B_CPU0_SB_DQ<19>")
	)
	(segment
		(start 338.434934 -228.459284)
		(end 338.43468 -228.45903)
		(width 0.20066)
		(layer "F.Cu")
		(net "M_B_CPU0_SB_DQ<19>")
	)
	(segment
		(start 292.689534 -211.341716)
		(end 292.67531 -211.35594)
		(width 0.101854)
		(layer "F.Cu")
		(net "M_B_CPU0_SB_DQ<19>")
	)
	(segment
		(start 296.217594 -210.912456)
		(end 295.82237 -210.912456)
		(width 0.20066)
		(layer "F.Cu")
		(net "M_B_CPU0_SB_DQ<19>")
	)
	(segment
		(start 295.693846 -211.192618)
		(end 295.544748 -211.341716)
		(width 0.20066)
		(layer "F.Cu")
		(net "M_B_CPU0_SB_DQ<19>")
	)
	(segment
		(start 292.321488 -211.35594)
		(end 292.178994 -211.213446)
		(width 0.20066)
		(layer "F.Cu")
		(net "M_B_CPU0_SB_DQ<19>")
	)
	(segment
		(start 317.520574 -210.940904)
		(end 316.966346 -210.940904)
		(width 0.18288)
		(layer "In2.Cu")
		(net "M_B_CPU0_SB_DQ<19>")
	)
	(segment
		(start 320.360294 -213.094824)
		(end 320.360294 -212.822028)
		(width 0.18288)
		(layer "In2.Cu")
		(net "M_B_CPU0_SB_DQ<19>")
	)
	(segment
		(start 332.530704 -225.468688)
		(end 332.381606 -225.319082)
		(width 0.088646)
		(layer "In2.Cu")
		(net "M_B_CPU0_SB_DQ<19>")
	)
	(segment
		(start 335.244948 -228.134672)
		(end 334.958182 -227.969318)
		(width 0.088646)
		(layer "In2.Cu")
		(net "M_B_CPU0_SB_DQ<19>")
	)
	(segment
		(start 320.859658 -213.594188)
		(end 320.644774 -213.809072)
		(width 0.18288)
		(layer "In2.Cu")
		(net "M_B_CPU0_SB_DQ<19>")
	)
	(segment
		(start 334.494378 -227.159058)
		(end 334.488282 -227.155502)
		(width 0.088646)
		(layer "In2.Cu")
		(net "M_B_CPU0_SB_DQ<19>")
	)
	(segment
		(start 314.04687 -210.52409)
		(end 312.092086 -210.52409)
		(width 0.18288)
		(layer "In2.Cu")
		(net "M_B_CPU0_SB_DQ<19>")
	)
	(segment
		(start 318.362838 -211.097368)
		(end 318.362838 -210.824572)
		(width 0.18288)
		(layer "In2.Cu")
		(net "M_B_CPU0_SB_DQ<19>")
	)
	(segment
		(start 322.131182 -214.592916)
		(end 321.858386 -214.592916)
		(width 0.18288)
		(layer "In2.Cu")
		(net "M_B_CPU0_SB_DQ<19>")
	)
	(segment
		(start 315.072776 -210.154774)
		(end 314.5282 -210.69935)
		(width 0.18288)
		(layer "In2.Cu")
		(net "M_B_CPU0_SB_DQ<19>")
	)
	(segment
		(start 322.142866 -215.57996)
		(end 322.142866 -215.307164)
		(width 0.18288)
		(layer "In2.Cu")
		(net "M_B_CPU0_SB_DQ<19>")
	)
	(segment
		(start 318.374522 -211.811616)
		(end 318.147954 -211.585048)
		(width 0.18288)
		(layer "In2.Cu")
		(net "M_B_CPU0_SB_DQ<19>")
	)
	(segment
		(start 318.647318 -211.811616)
		(end 318.374522 -211.811616)
		(width 0.18288)
		(layer "In2.Cu")
		(net "M_B_CPU0_SB_DQ<19>")
	)
	(segment
		(start 319.134998 -211.596732)
		(end 318.862202 -211.596732)
		(width 0.18288)
		(layer "In2.Cu")
		(net "M_B_CPU0_SB_DQ<19>")
	)
	(segment
		(start 317.863474 -210.598004)
		(end 317.520574 -210.940904)
		(width 0.18288)
		(layer "In2.Cu")
		(net "M_B_CPU0_SB_DQ<19>")
	)
	(segment
		(start 322.397628 -215.834722)
		(end 322.142866 -215.57996)
		(width 0.18288)
		(layer "In2.Cu")
		(net "M_B_CPU0_SB_DQ<19>")
	)
	(segment
		(start 307.510434 -210.484974)
		(end 307.214778 -210.78063)
		(width 0.18288)
		(layer "In2.Cu")
		(net "M_B_CPU0_SB_DQ<19>")
	)
	(segment
		(start 318.862202 -211.596732)
		(end 318.647318 -211.811616)
		(width 0.18288)
		(layer "In2.Cu")
		(net "M_B_CPU0_SB_DQ<19>")
	)
	(segment
		(start 322.142866 -215.307164)
		(end 322.35775 -215.09228)
		(width 0.18288)
		(layer "In2.Cu")
		(net "M_B_CPU0_SB_DQ<19>")
	)
	(segment
		(start 321.370706 -214.8078)
		(end 321.144138 -214.581232)
		(width 0.18288)
		(layer "In2.Cu")
		(net "M_B_CPU0_SB_DQ<19>")
	)
	(segment
		(start 314.5282 -210.69935)
		(end 314.22213 -210.69935)
		(width 0.18288)
		(layer "In2.Cu")
		(net "M_B_CPU0_SB_DQ<19>")
	)
	(segment
		(start 319.361566 -211.8233)
		(end 319.134998 -211.596732)
		(width 0.18288)
		(layer "In2.Cu")
		(net "M_B_CPU0_SB_DQ<19>")
	)
	(segment
		(start 322.670678 -215.834722)
		(end 322.397628 -215.834722)
		(width 0.18288)
		(layer "In2.Cu")
		(net "M_B_CPU0_SB_DQ<19>")
	)
	(segment
		(start 334.018636 -226.341686)
		(end 334.009746 -226.336606)
		(width 0.088646)
		(layer "In2.Cu")
		(net "M_B_CPU0_SB_DQ<19>")
	)
	(segment
		(start 323.113654 -215.581992)
		(end 322.923408 -215.581992)
		(width 0.18288)
		(layer "In2.Cu")
		(net "M_B_CPU0_SB_DQ<19>")
	)
	(segment
		(start 311.84215 -210.774026)
		(end 311.11444 -210.774026)
		(width 0.18288)
		(layer "In2.Cu")
		(net "M_B_CPU0_SB_DQ<19>")
	)
	(segment
		(start 310.9214 -210.117436)
		(end 310.72836 -209.924396)
		(width 0.18288)
		(layer "In2.Cu")
		(net "M_B_CPU0_SB_DQ<19>")
	)
	(segment
		(start 322.35775 -215.09228)
		(end 322.35775 -214.819484)
		(width 0.18288)
		(layer "In2.Cu")
		(net "M_B_CPU0_SB_DQ<19>")
	)
	(segment
		(start 321.858386 -214.592916)
		(end 321.643502 -214.8078)
		(width 0.18288)
		(layer "In2.Cu")
		(net "M_B_CPU0_SB_DQ<19>")
	)
	(segment
		(start 332.998064 -225.51898)
		(end 332.983332 -225.527616)
		(width 0.088646)
		(layer "In2.Cu")
		(net "M_B_CPU0_SB_DQ<19>")
	)
	(segment
		(start 321.144138 -214.581232)
		(end 321.144138 -214.308436)
		(width 0.18288)
		(layer "In2.Cu")
		(net "M_B_CPU0_SB_DQ<19>")
	)
	(segment
		(start 311.11444 -210.774026)
		(end 310.9214 -210.580986)
		(width 0.18288)
		(layer "In2.Cu")
		(net "M_B_CPU0_SB_DQ<19>")
	)
	(segment
		(start 322.923408 -215.581992)
		(end 322.670678 -215.834722)
		(width 0.18288)
		(layer "In2.Cu")
		(net "M_B_CPU0_SB_DQ<19>")
	)
	(segment
		(start 336.368136 -228.134672)
		(end 336.367882 -228.134672)
		(width 0.088646)
		(layer "In2.Cu")
		(net "M_B_CPU0_SB_DQ<19>")
	)
	(segment
		(start 319.646046 -212.810344)
		(end 319.37325 -212.810344)
		(width 0.18288)
		(layer "In2.Cu")
		(net "M_B_CPU0_SB_DQ<19>")
	)
	(segment
		(start 306.527962 -210.78063)
		(end 306.271422 -210.52409)
		(width 0.18288)
		(layer "In2.Cu")
		(net "M_B_CPU0_SB_DQ<19>")
	)
	(segment
		(start 304.522124 -210.52409)
		(end 304.46472 -210.581494)
		(width 0.18288)
		(layer "In2.Cu")
		(net "M_B_CPU0_SB_DQ<19>")
	)
	(segment
		(start 336.367882 -228.134672)
		(end 336.357468 -228.140768)
		(width 0.088646)
		(layer "In2.Cu")
		(net "M_B_CPU0_SB_DQ<19>")
	)
	(segment
		(start 332.381606 -225.319082)
		(end 332.381606 -224.849944)
		(width 0.088646)
		(layer "In2.Cu")
		(net "M_B_CPU0_SB_DQ<19>")
	)
	(segment
		(start 310.447944 -209.924396)
		(end 309.887366 -210.484974)
		(width 0.18288)
		(layer "In2.Cu")
		(net "M_B_CPU0_SB_DQ<19>")
	)
	(segment
		(start 321.359022 -214.093552)
		(end 321.359022 -213.820756)
		(width 0.18288)
		(layer "In2.Cu")
		(net "M_B_CPU0_SB_DQ<19>")
	)
	(segment
		(start 309.887366 -210.484974)
		(end 307.510434 -210.484974)
		(width 0.18288)
		(layer "In2.Cu")
		(net "M_B_CPU0_SB_DQ<19>")
	)
	(segment
		(start 320.14541 -213.582504)
		(end 320.14541 -213.309708)
		(width 0.18288)
		(layer "In2.Cu")
		(net "M_B_CPU0_SB_DQ<19>")
	)
	(segment
		(start 319.86093 -212.59546)
		(end 319.646046 -212.810344)
		(width 0.18288)
		(layer "In2.Cu")
		(net "M_B_CPU0_SB_DQ<19>")
	)
	(segment
		(start 320.14541 -213.309708)
		(end 320.360294 -213.094824)
		(width 0.18288)
		(layer "In2.Cu")
		(net "M_B_CPU0_SB_DQ<19>")
	)
	(segment
		(start 334.770984 -227.645214)
		(end 334.770984 -227.64496)
		(width 0.088646)
		(layer "In2.Cu")
		(net "M_B_CPU0_SB_DQ<19>")
	)
	(segment
		(start 299.469556 -211.381848)
		(end 299.004482 -210.916774)
		(width 0.18288)
		(layer "In2.Cu")
		(net "M_B_CPU0_SB_DQ<19>")
	)
	(segment
		(start 314.22213 -210.69935)
		(end 314.04687 -210.52409)
		(width 0.18288)
		(layer "In2.Cu")
		(net "M_B_CPU0_SB_DQ<19>")
	)
	(segment
		(start 319.361566 -212.096096)
		(end 319.361566 -211.8233)
		(width 0.18288)
		(layer "In2.Cu")
		(net "M_B_CPU0_SB_DQ<19>")
	)
	(segment
		(start 318.362838 -210.824572)
		(end 318.13627 -210.598004)
		(width 0.18288)
		(layer "In2.Cu")
		(net "M_B_CPU0_SB_DQ<19>")
	)
	(segment
		(start 306.271422 -210.52409)
		(end 304.522124 -210.52409)
		(width 0.18288)
		(layer "In2.Cu")
		(net "M_B_CPU0_SB_DQ<19>")
	)
	(segment
		(start 320.644774 -213.809072)
		(end 320.371978 -213.809072)
		(width 0.18288)
		(layer "In2.Cu")
		(net "M_B_CPU0_SB_DQ<19>")
	)
	(segment
		(start 318.13627 -210.598004)
		(end 317.863474 -210.598004)
		(width 0.18288)
		(layer "In2.Cu")
		(net "M_B_CPU0_SB_DQ<19>")
	)
	(segment
		(start 307.214778 -210.78063)
		(end 306.527962 -210.78063)
		(width 0.18288)
		(layer "In2.Cu")
		(net "M_B_CPU0_SB_DQ<19>")
	)
	(segment
		(start 310.72836 -209.924396)
		(end 310.447944 -209.924396)
		(width 0.18288)
		(layer "In2.Cu")
		(net "M_B_CPU0_SB_DQ<19>")
	)
	(segment
		(start 303.62144 -210.581494)
		(end 302.821086 -211.381848)
		(width 0.18288)
		(layer "In2.Cu")
		(net "M_B_CPU0_SB_DQ<19>")
	)
	(segment
		(start 320.133726 -212.59546)
		(end 319.86093 -212.59546)
		(width 0.18288)
		(layer "In2.Cu")
		(net "M_B_CPU0_SB_DQ<19>")
	)
	(segment
		(start 321.359022 -213.820756)
		(end 321.132454 -213.594188)
		(width 0.18288)
		(layer "In2.Cu")
		(net "M_B_CPU0_SB_DQ<19>")
	)
	(segment
		(start 318.147954 -211.585048)
		(end 318.147954 -211.312252)
		(width 0.18288)
		(layer "In2.Cu")
		(net "M_B_CPU0_SB_DQ<19>")
	)
	(segment
		(start 322.35775 -214.819484)
		(end 322.131182 -214.592916)
		(width 0.18288)
		(layer "In2.Cu")
		(net "M_B_CPU0_SB_DQ<19>")
	)
	(segment
		(start 334.301084 -226.83978)
		(end 334.301084 -226.821238)
		(width 0.088646)
		(layer "In2.Cu")
		(net "M_B_CPU0_SB_DQ<19>")
	)
	(segment
		(start 321.144138 -214.308436)
		(end 321.359022 -214.093552)
		(width 0.18288)
		(layer "In2.Cu")
		(net "M_B_CPU0_SB_DQ<19>")
	)
	(segment
		(start 335.802732 -228.134672)
		(end 335.802478 -228.134672)
		(width 0.088646)
		(layer "In2.Cu")
		(net "M_B_CPU0_SB_DQ<19>")
	)
	(segment
		(start 319.146682 -212.583776)
		(end 319.146682 -212.31098)
		(width 0.18288)
		(layer "In2.Cu")
		(net "M_B_CPU0_SB_DQ<19>")
	)
	(segment
		(start 333.831184 -226.017328)
		(end 333.831184 -226.003104)
		(width 0.088646)
		(layer "In2.Cu")
		(net "M_B_CPU0_SB_DQ<19>")
	)
	(segment
		(start 319.37325 -212.810344)
		(end 319.146682 -212.583776)
		(width 0.18288)
		(layer "In2.Cu")
		(net "M_B_CPU0_SB_DQ<19>")
	)
	(segment
		(start 304.46472 -210.581494)
		(end 303.62144 -210.581494)
		(width 0.18288)
		(layer "In2.Cu")
		(net "M_B_CPU0_SB_DQ<19>")
	)
	(segment
		(start 318.147954 -211.312252)
		(end 318.362838 -211.097368)
		(width 0.18288)
		(layer "In2.Cu")
		(net "M_B_CPU0_SB_DQ<19>")
	)
	(segment
		(start 319.146682 -212.31098)
		(end 319.361566 -212.096096)
		(width 0.18288)
		(layer "In2.Cu")
		(net "M_B_CPU0_SB_DQ<19>")
	)
	(segment
		(start 332.381606 -224.849944)
		(end 332.076806 -224.545144)
		(width 0.088646)
		(layer "In2.Cu")
		(net "M_B_CPU0_SB_DQ<19>")
	)
	(segment
		(start 316.966346 -210.940904)
		(end 316.180216 -210.154774)
		(width 0.18288)
		(layer "In2.Cu")
		(net "M_B_CPU0_SB_DQ<19>")
	)
	(segment
		(start 302.821086 -211.381848)
		(end 299.469556 -211.381848)
		(width 0.18288)
		(layer "In2.Cu")
		(net "M_B_CPU0_SB_DQ<19>")
	)
	(segment
		(start 310.9214 -210.580986)
		(end 310.9214 -210.117436)
		(width 0.18288)
		(layer "In2.Cu")
		(net "M_B_CPU0_SB_DQ<19>")
	)
	(segment
		(start 321.132454 -213.594188)
		(end 320.859658 -213.594188)
		(width 0.18288)
		(layer "In2.Cu")
		(net "M_B_CPU0_SB_DQ<19>")
	)
	(segment
		(start 312.092086 -210.52409)
		(end 311.84215 -210.774026)
		(width 0.18288)
		(layer "In2.Cu")
		(net "M_B_CPU0_SB_DQ<19>")
	)
	(segment
		(start 316.180216 -210.154774)
		(end 315.072776 -210.154774)
		(width 0.18288)
		(layer "In2.Cu")
		(net "M_B_CPU0_SB_DQ<19>")
	)
	(segment
		(start 320.371978 -213.809072)
		(end 320.14541 -213.582504)
		(width 0.18288)
		(layer "In2.Cu")
		(net "M_B_CPU0_SB_DQ<19>")
	)
	(segment
		(start 338.080858 -228.364288)
		(end 337.67649 -228.131116)
		(width 0.088646)
		(layer "In2.Cu")
		(net "M_B_CPU0_SB_DQ<19>")
	)
	(segment
		(start 332.076806 -224.545144)
		(end 323.113654 -215.581992)
		(width 0.18288)
		(layer "In2.Cu")
		(net "M_B_CPU0_SB_DQ<19>")
	)
	(segment
		(start 320.360294 -212.822028)
		(end 320.133726 -212.59546)
		(width 0.18288)
		(layer "In2.Cu")
		(net "M_B_CPU0_SB_DQ<19>")
	)
	(segment
		(start 321.643502 -214.8078)
		(end 321.370706 -214.8078)
		(width 0.18288)
		(layer "In2.Cu")
		(net "M_B_CPU0_SB_DQ<19>")
	)
	(arc
		(start 333.548736 -225.527616)
		(mid 333.274507 -225.451691)
		(end 332.998064 -225.51898)
		(width 0.088646)
		(layer "In2.Cu")
		(net "M_B_CPU0_SB_DQ<19>")
	)
	(arc
		(start 334.488282 -227.155502)
		(mid 334.353349 -227.022148)
		(end 334.301084 -226.83978)
		(width 0.088646)
		(layer "In2.Cu")
		(net "M_B_CPU0_SB_DQ<19>")
	)
	(arc
		(start 336.742786 -228.134672)
		(mid 336.555478 -228.084563)
		(end 336.368136 -228.134672)
		(width 0.088646)
		(layer "In2.Cu")
		(net "M_B_CPU0_SB_DQ<19>")
	)
	(arc
		(start 334.770984 -227.64496)
		(mid 334.696993 -227.365394)
		(end 334.494378 -227.159058)
		(width 0.088646)
		(layer "In2.Cu")
		(net "M_B_CPU0_SB_DQ<19>")
	)
	(arc
		(start 335.428336 -228.134672)
		(mid 335.336642 -228.159251)
		(end 335.244948 -228.134672)
		(width 0.088646)
		(layer "In2.Cu")
		(net "M_B_CPU0_SB_DQ<19>")
	)
	(arc
		(start 336.357468 -228.140768)
		(mid 336.07929 -228.21046)
		(end 335.802732 -228.134672)
		(width 0.088646)
		(layer "In2.Cu")
		(net "M_B_CPU0_SB_DQ<19>")
	)
	(arc
		(start 335.802478 -228.134672)
		(mid 335.615424 -228.084622)
		(end 335.428336 -228.134672)
		(width 0.088646)
		(layer "In2.Cu")
		(net "M_B_CPU0_SB_DQ<19>")
	)
	(arc
		(start 332.983332 -225.527616)
		(mid 332.796134 -225.577759)
		(end 332.608936 -225.527616)
		(width 0.088646)
		(layer "In2.Cu")
		(net "M_B_CPU0_SB_DQ<19>")
	)
	(arc
		(start 338.43468 -228.45903)
		(mid 338.251563 -228.434854)
		(end 338.080858 -228.364288)
		(width 0.088646)
		(layer "In2.Cu")
		(net "M_B_CPU0_SB_DQ<19>")
	)
	(arc
		(start 334.009746 -226.336606)
		(mid 333.878832 -226.200246)
		(end 333.831184 -226.017328)
		(width 0.088646)
		(layer "In2.Cu")
		(net "M_B_CPU0_SB_DQ<19>")
	)
	(arc
		(start 333.831184 -226.003104)
		(mid 333.752043 -225.728481)
		(end 333.548736 -225.527616)
		(width 0.088646)
		(layer "In2.Cu")
		(net "M_B_CPU0_SB_DQ<19>")
	)
	(arc
		(start 334.301084 -226.821238)
		(mid 334.222973 -226.544289)
		(end 334.018636 -226.341686)
		(width 0.088646)
		(layer "In2.Cu")
		(net "M_B_CPU0_SB_DQ<19>")
	)
	(arc
		(start 332.608936 -225.527616)
		(mid 332.567878 -225.500729)
		(end 332.530704 -225.468688)
		(width 0.088646)
		(layer "In2.Cu")
		(net "M_B_CPU0_SB_DQ<19>")
	)
	(arc
		(start 334.958182 -227.969318)
		(mid 334.821137 -227.832358)
		(end 334.770984 -227.645214)
		(width 0.088646)
		(layer "In2.Cu")
		(net "M_B_CPU0_SB_DQ<19>")
	)
	(arc
		(start 337.307682 -228.134418)
		(mid 337.025263 -228.210228)
		(end 336.742786 -228.134672)
		(width 0.088646)
		(layer "In2.Cu")
		(net "M_B_CPU0_SB_DQ<19>")
	)
	(arc
		(start 337.67649 -228.131116)
		(mid 337.491635 -228.084198)
		(end 337.307682 -228.134418)
		(width 0.088646)
		(layer "In2.Cu")
		(net "M_B_CPU0_SB_DQ<19>")
	)
	(segment
		(start 291.502846 -212.616796)
		(end 290.355782 -212.616796)
		(width 0.20066)
		(layer "F.Cu")
		(net "M_B_CPU0_SB_DQ<18>")
	)
	(segment
		(start 295.944544 -212.828632)
		(end 295.777158 -212.661246)
		(width 0.20066)
		(layer "F.Cu")
		(net "M_B_CPU0_SB_DQ<18>")
	)
	(segment
		(start 297.899582 -212.616796)
		(end 296.584878 -212.616796)
		(width 0.20066)
		(layer "F.Cu")
		(net "M_B_CPU0_SB_DQ<18>")
	)
	(segment
		(start 295.777158 -212.661246)
		(end 295.777158 -212.335618)
		(width 0.20066)
		(layer "F.Cu")
		(net "M_B_CPU0_SB_DQ<18>")
	)
	(segment
		(start 292.940486 -212.191854)
		(end 292.68547 -212.191854)
		(width 0.101854)
		(layer "F.Cu")
		(net "M_B_CPU0_SB_DQ<18>")
	)
	(segment
		(start 296.584878 -212.616796)
		(end 296.373042 -212.828632)
		(width 0.20066)
		(layer "F.Cu")
		(net "M_B_CPU0_SB_DQ<18>")
	)
	(segment
		(start 296.373042 -212.828632)
		(end 295.944544 -212.828632)
		(width 0.20066)
		(layer "F.Cu")
		(net "M_B_CPU0_SB_DQ<18>")
	)
	(segment
		(start 295.633394 -212.191854)
		(end 295.000426 -212.191854)
		(width 0.20066)
		(layer "F.Cu")
		(net "M_B_CPU0_SB_DQ<18>")
	)
	(segment
		(start 291.937948 -212.181694)
		(end 291.502846 -212.616796)
		(width 0.20066)
		(layer "F.Cu")
		(net "M_B_CPU0_SB_DQ<18>")
	)
	(segment
		(start 295.000426 -212.191854)
		(end 292.940486 -212.191854)
		(width 0.1016)
		(layer "F.Cu")
		(net "M_B_CPU0_SB_DQ<18>")
	)
	(segment
		(start 295.777158 -212.335618)
		(end 295.633394 -212.191854)
		(width 0.20066)
		(layer "F.Cu")
		(net "M_B_CPU0_SB_DQ<18>")
	)
	(segment
		(start 292.68547 -212.191854)
		(end 292.67531 -212.181694)
		(width 0.101854)
		(layer "F.Cu")
		(net "M_B_CPU0_SB_DQ<18>")
	)
	(segment
		(start 299.004482 -212.616796)
		(end 297.899582 -212.616796)
		(width 0.20066)
		(layer "F.Cu")
		(net "M_B_CPU0_SB_DQ<18>")
	)
	(segment
		(start 337.96478 -229.808786)
		(end 337.965034 -229.808532)
		(width 0.20066)
		(layer "F.Cu")
		(net "M_B_CPU0_SB_DQ<18>")
	)
	(segment
		(start 337.965034 -229.808532)
		(end 337.965034 -229.272846)
		(width 0.20066)
		(layer "F.Cu")
		(net "M_B_CPU0_SB_DQ<18>")
	)
	(segment
		(start 292.67531 -212.181694)
		(end 291.937948 -212.181694)
		(width 0.20066)
		(layer "F.Cu")
		(net "M_B_CPU0_SB_DQ<18>")
	)
	(segment
		(start 330.65847 -224.640394)
		(end 330.431902 -224.413826)
		(width 0.18288)
		(layer "In2.Cu")
		(net "M_B_CPU0_SB_DQ<18>")
	)
	(segment
		(start 328.485246 -223.364044)
		(end 328.485246 -223.091248)
		(width 0.18288)
		(layer "In2.Cu")
		(net "M_B_CPU0_SB_DQ<18>")
	)
	(segment
		(start 302.636682 -213.092792)
		(end 300.079156 -213.092792)
		(width 0.18288)
		(layer "In2.Cu")
		(net "M_B_CPU0_SB_DQ<18>")
	)
	(segment
		(start 323.491606 -218.370404)
		(end 323.491606 -218.097608)
		(width 0.18288)
		(layer "In2.Cu")
		(net "M_B_CPU0_SB_DQ<18>")
	)
	(segment
		(start 323.99097 -218.596972)
		(end 323.718174 -218.596972)
		(width 0.18288)
		(layer "In2.Cu")
		(net "M_B_CPU0_SB_DQ<18>")
	)
	(segment
		(start 334.301084 -228.45903)
		(end 334.301084 -228.440488)
		(width 0.088646)
		(layer "In2.Cu")
		(net "M_B_CPU0_SB_DQ<18>")
	)
	(segment
		(start 333.090774 -226.348798)
		(end 333.078582 -226.341686)
		(width 0.088646)
		(layer "In2.Cu")
		(net "M_B_CPU0_SB_DQ<18>")
	)
	(segment
		(start 325.66483 -219.91955)
		(end 325.66483 -219.646754)
		(width 0.18288)
		(layer "In2.Cu")
		(net "M_B_CPU0_SB_DQ<18>")
	)
	(segment
		(start 326.663558 -220.645482)
		(end 326.43699 -220.418914)
		(width 0.18288)
		(layer "In2.Cu")
		(net "M_B_CPU0_SB_DQ<18>")
	)
	(segment
		(start 326.48779 -221.093792)
		(end 326.663558 -220.918278)
		(width 0.18288)
		(layer "In2.Cu")
		(net "M_B_CPU0_SB_DQ<18>")
	)
	(segment
		(start 329.659742 -223.914462)
		(end 329.659742 -223.641666)
		(width 0.18288)
		(layer "In2.Cu")
		(net "M_B_CPU0_SB_DQ<18>")
	)
	(segment
		(start 313.569858 -211.923884)
		(end 312.390282 -211.923884)
		(width 0.18288)
		(layer "In2.Cu")
		(net "M_B_CPU0_SB_DQ<18>")
	)
	(segment
		(start 311.44591 -212.236304)
		(end 311.273698 -212.064092)
		(width 0.18288)
		(layer "In2.Cu")
		(net "M_B_CPU0_SB_DQ<18>")
	)
	(segment
		(start 332.79588 -226.265994)
		(end 332.562962 -226.265994)
		(width 0.088646)
		(layer "In2.Cu")
		(net "M_B_CPU0_SB_DQ<18>")
	)
	(segment
		(start 312.390282 -211.923884)
		(end 312.077862 -212.236304)
		(width 0.18288)
		(layer "In2.Cu")
		(net "M_B_CPU0_SB_DQ<18>")
	)
	(segment
		(start 330.65847 -224.91319)
		(end 330.65847 -224.640394)
		(width 0.18288)
		(layer "In2.Cu")
		(net "M_B_CPU0_SB_DQ<18>")
	)
	(segment
		(start 306.363116 -212.246972)
		(end 306.045616 -211.929472)
		(width 0.18288)
		(layer "In2.Cu")
		(net "M_B_CPU0_SB_DQ<18>")
	)
	(segment
		(start 304.85461 -211.929472)
		(end 304.53711 -212.246972)
		(width 0.18288)
		(layer "In2.Cu")
		(net "M_B_CPU0_SB_DQ<18>")
	)
	(segment
		(start 333.554832 -227.159058)
		(end 333.548736 -227.155502)
		(width 0.088646)
		(layer "In2.Cu")
		(net "M_B_CPU0_SB_DQ<18>")
	)
	(segment
		(start 327.662286 -221.917006)
		(end 327.662286 -221.64421)
		(width 0.18288)
		(layer "In2.Cu")
		(net "M_B_CPU0_SB_DQ<18>")
	)
	(segment
		(start 324.166738 -218.421458)
		(end 323.99097 -218.596972)
		(width 0.18288)
		(layer "In2.Cu")
		(net "M_B_CPU0_SB_DQ<18>")
	)
	(segment
		(start 326.164194 -220.418914)
		(end 325.988426 -220.594428)
		(width 0.18288)
		(layer "In2.Cu")
		(net "M_B_CPU0_SB_DQ<18>")
	)
	(segment
		(start 324.666102 -218.920822)
		(end 324.666102 -218.648026)
		(width 0.18288)
		(layer "In2.Cu")
		(net "M_B_CPU0_SB_DQ<18>")
	)
	(segment
		(start 327.486518 -222.365316)
		(end 327.486518 -222.09252)
		(width 0.18288)
		(layer "In2.Cu")
		(net "M_B_CPU0_SB_DQ<18>")
	)
	(segment
		(start 329.160378 -223.415098)
		(end 328.98461 -223.590612)
		(width 0.18288)
		(layer "In2.Cu")
		(net "M_B_CPU0_SB_DQ<18>")
	)
	(segment
		(start 329.483974 -224.362772)
		(end 329.483974 -224.089976)
		(width 0.18288)
		(layer "In2.Cu")
		(net "M_B_CPU0_SB_DQ<18>")
	)
	(segment
		(start 329.983338 -224.58934)
		(end 329.710542 -224.58934)
		(width 0.18288)
		(layer "In2.Cu")
		(net "M_B_CPU0_SB_DQ<18>")
	)
	(segment
		(start 323.667374 -217.649298)
		(end 323.440806 -217.42273)
		(width 0.18288)
		(layer "In2.Cu")
		(net "M_B_CPU0_SB_DQ<18>")
	)
	(segment
		(start 325.66483 -219.646754)
		(end 325.438262 -219.420186)
		(width 0.18288)
		(layer "In2.Cu")
		(net "M_B_CPU0_SB_DQ<18>")
	)
	(segment
		(start 325.988426 -220.594428)
		(end 325.71563 -220.594428)
		(width 0.18288)
		(layer "In2.Cu")
		(net "M_B_CPU0_SB_DQ<18>")
	)
	(segment
		(start 327.985882 -222.591884)
		(end 327.713086 -222.591884)
		(width 0.18288)
		(layer "In2.Cu")
		(net "M_B_CPU0_SB_DQ<18>")
	)
	(segment
		(start 329.710542 -224.58934)
		(end 329.483974 -224.362772)
		(width 0.18288)
		(layer "In2.Cu")
		(net "M_B_CPU0_SB_DQ<18>")
	)
	(segment
		(start 327.162922 -221.417642)
		(end 326.987154 -221.593156)
		(width 0.18288)
		(layer "In2.Cu")
		(net "M_B_CPU0_SB_DQ<18>")
	)
	(segment
		(start 323.718174 -218.596972)
		(end 323.491606 -218.370404)
		(width 0.18288)
		(layer "In2.Cu")
		(net "M_B_CPU0_SB_DQ<18>")
	)
	(segment
		(start 330.159106 -224.413826)
		(end 329.983338 -224.58934)
		(width 0.18288)
		(layer "In2.Cu")
		(net "M_B_CPU0_SB_DQ<18>")
	)
	(segment
		(start 309.51297 -212.323172)
		(end 308.180994 -212.323172)
		(width 0.18288)
		(layer "In2.Cu")
		(net "M_B_CPU0_SB_DQ<18>")
	)
	(segment
		(start 334.488536 -228.783388)
		(end 334.488282 -228.783134)
		(width 0.088646)
		(layer "In2.Cu")
		(net "M_B_CPU0_SB_DQ<18>")
	)
	(segment
		(start 337.965034 -229.272846)
		(end 337.905598 -229.272846)
		(width 0.088646)
		(layer "In2.Cu")
		(net "M_B_CPU0_SB_DQ<18>")
	)
	(segment
		(start 328.16165 -222.41637)
		(end 327.985882 -222.591884)
		(width 0.18288)
		(layer "In2.Cu")
		(net "M_B_CPU0_SB_DQ<18>")
	)
	(segment
		(start 331.062584 -225.941382)
		(end 330.482702 -225.3615)
		(width 0.18288)
		(layer "In2.Cu")
		(net "M_B_CPU0_SB_DQ<18>")
	)
	(segment
		(start 330.482702 -225.3615)
		(end 330.482702 -225.088704)
		(width 0.18288)
		(layer "In2.Cu")
		(net "M_B_CPU0_SB_DQ<18>")
	)
	(segment
		(start 328.661014 -222.915734)
		(end 328.661014 -222.642938)
		(width 0.18288)
		(layer "In2.Cu")
		(net "M_B_CPU0_SB_DQ<18>")
	)
	(segment
		(start 307.16855 -212.246972)
		(end 306.363116 -212.246972)
		(width 0.18288)
		(layer "In2.Cu")
		(net "M_B_CPU0_SB_DQ<18>")
	)
	(segment
		(start 326.43699 -220.418914)
		(end 326.164194 -220.418914)
		(width 0.18288)
		(layer "In2.Cu")
		(net "M_B_CPU0_SB_DQ<18>")
	)
	(segment
		(start 308.180994 -212.323172)
		(end 307.967634 -212.109812)
		(width 0.18288)
		(layer "In2.Cu")
		(net "M_B_CPU0_SB_DQ<18>")
	)
	(segment
		(start 314.46978 -212.12048)
		(end 314.353956 -212.236304)
		(width 0.18288)
		(layer "In2.Cu")
		(net "M_B_CPU0_SB_DQ<18>")
	)
	(segment
		(start 324.490334 -219.369132)
		(end 324.490334 -219.096336)
		(width 0.18288)
		(layer "In2.Cu")
		(net "M_B_CPU0_SB_DQ<18>")
	)
	(segment
		(start 304.53711 -212.246972)
		(end 303.482502 -212.246972)
		(width 0.18288)
		(layer "In2.Cu")
		(net "M_B_CPU0_SB_DQ<18>")
	)
	(segment
		(start 303.482502 -212.246972)
		(end 302.636682 -213.092792)
		(width 0.18288)
		(layer "In2.Cu")
		(net "M_B_CPU0_SB_DQ<18>")
	)
	(segment
		(start 326.663558 -220.918278)
		(end 326.663558 -220.645482)
		(width 0.18288)
		(layer "In2.Cu")
		(net "M_B_CPU0_SB_DQ<18>")
	)
	(segment
		(start 335.33588 -228.950012)
		(end 335.332832 -228.948488)
		(width 0.088646)
		(layer "In2.Cu")
		(net "M_B_CPU0_SB_DQ<18>")
	)
	(segment
		(start 324.989698 -219.5957)
		(end 324.716902 -219.5957)
		(width 0.18288)
		(layer "In2.Cu")
		(net "M_B_CPU0_SB_DQ<18>")
	)
	(segment
		(start 326.714358 -221.593156)
		(end 326.48779 -221.366588)
		(width 0.18288)
		(layer "In2.Cu")
		(net "M_B_CPU0_SB_DQ<18>")
	)
	(segment
		(start 330.482702 -225.088704)
		(end 330.65847 -224.91319)
		(width 0.18288)
		(layer "In2.Cu")
		(net "M_B_CPU0_SB_DQ<18>")
	)
	(segment
		(start 325.71563 -220.594428)
		(end 325.489062 -220.36786)
		(width 0.18288)
		(layer "In2.Cu")
		(net "M_B_CPU0_SB_DQ<18>")
	)
	(segment
		(start 322.992242 -217.598244)
		(end 322.719446 -217.598244)
		(width 0.18288)
		(layer "In2.Cu")
		(net "M_B_CPU0_SB_DQ<18>")
	)
	(segment
		(start 326.987154 -221.593156)
		(end 326.714358 -221.593156)
		(width 0.18288)
		(layer "In2.Cu")
		(net "M_B_CPU0_SB_DQ<18>")
	)
	(segment
		(start 317.241682 -212.12048)
		(end 314.46978 -212.12048)
		(width 0.18288)
		(layer "In2.Cu")
		(net "M_B_CPU0_SB_DQ<18>")
	)
	(segment
		(start 323.491606 -218.097608)
		(end 323.667374 -217.922094)
		(width 0.18288)
		(layer "In2.Cu")
		(net "M_B_CPU0_SB_DQ<18>")
	)
	(segment
		(start 323.440806 -217.42273)
		(end 323.16801 -217.42273)
		(width 0.18288)
		(layer "In2.Cu")
		(net "M_B_CPU0_SB_DQ<18>")
	)
	(segment
		(start 325.438262 -219.420186)
		(end 325.165466 -219.420186)
		(width 0.18288)
		(layer "In2.Cu")
		(net "M_B_CPU0_SB_DQ<18>")
	)
	(segment
		(start 329.659742 -223.641666)
		(end 329.433174 -223.415098)
		(width 0.18288)
		(layer "In2.Cu")
		(net "M_B_CPU0_SB_DQ<18>")
	)
	(segment
		(start 329.433174 -223.415098)
		(end 329.160378 -223.415098)
		(width 0.18288)
		(layer "In2.Cu")
		(net "M_B_CPU0_SB_DQ<18>")
	)
	(segment
		(start 314.353956 -212.236304)
		(end 313.882278 -212.236304)
		(width 0.18288)
		(layer "In2.Cu")
		(net "M_B_CPU0_SB_DQ<18>")
	)
	(segment
		(start 324.439534 -218.421458)
		(end 324.166738 -218.421458)
		(width 0.18288)
		(layer "In2.Cu")
		(net "M_B_CPU0_SB_DQ<18>")
	)
	(segment
		(start 325.489062 -220.095064)
		(end 325.66483 -219.91955)
		(width 0.18288)
		(layer "In2.Cu")
		(net "M_B_CPU0_SB_DQ<18>")
	)
	(segment
		(start 337.52663 -229.129844)
		(end 337.212432 -228.948234)
		(width 0.088646)
		(layer "In2.Cu")
		(net "M_B_CPU0_SB_DQ<18>")
	)
	(segment
		(start 328.661014 -222.642938)
		(end 328.434446 -222.41637)
		(width 0.18288)
		(layer "In2.Cu")
		(net "M_B_CPU0_SB_DQ<18>")
	)
	(segment
		(start 332.076806 -225.941382)
		(end 331.062584 -225.941382)
		(width 0.18288)
		(layer "In2.Cu")
		(net "M_B_CPU0_SB_DQ<18>")
	)
	(segment
		(start 312.077862 -212.236304)
		(end 311.44591 -212.236304)
		(width 0.18288)
		(layer "In2.Cu")
		(net "M_B_CPU0_SB_DQ<18>")
	)
	(segment
		(start 327.435718 -221.417642)
		(end 327.162922 -221.417642)
		(width 0.18288)
		(layer "In2.Cu")
		(net "M_B_CPU0_SB_DQ<18>")
	)
	(segment
		(start 336.272632 -228.948488)
		(end 336.272378 -228.948488)
		(width 0.088646)
		(layer "In2.Cu")
		(net "M_B_CPU0_SB_DQ<18>")
	)
	(segment
		(start 328.98461 -223.590612)
		(end 328.711814 -223.590612)
		(width 0.18288)
		(layer "In2.Cu")
		(net "M_B_CPU0_SB_DQ<18>")
	)
	(segment
		(start 332.23835 -225.941382)
		(end 332.076806 -225.941382)
		(width 0.088646)
		(layer "In2.Cu")
		(net "M_B_CPU0_SB_DQ<18>")
	)
	(segment
		(start 333.548736 -227.155502)
		(end 333.539846 -227.150422)
		(width 0.088646)
		(layer "In2.Cu")
		(net "M_B_CPU0_SB_DQ<18>")
	)
	(segment
		(start 328.434446 -222.41637)
		(end 328.16165 -222.41637)
		(width 0.18288)
		(layer "In2.Cu")
		(net "M_B_CPU0_SB_DQ<18>")
	)
	(segment
		(start 325.489062 -220.36786)
		(end 325.489062 -220.095064)
		(width 0.18288)
		(layer "In2.Cu")
		(net "M_B_CPU0_SB_DQ<18>")
	)
	(segment
		(start 322.719446 -217.598244)
		(end 317.241682 -212.12048)
		(width 0.18288)
		(layer "In2.Cu")
		(net "M_B_CPU0_SB_DQ<18>")
	)
	(segment
		(start 299.60316 -212.616796)
		(end 299.004482 -212.616796)
		(width 0.18288)
		(layer "In2.Cu")
		(net "M_B_CPU0_SB_DQ<18>")
	)
	(segment
		(start 324.716902 -219.5957)
		(end 324.490334 -219.369132)
		(width 0.18288)
		(layer "In2.Cu")
		(net "M_B_CPU0_SB_DQ<18>")
	)
	(segment
		(start 327.713086 -222.591884)
		(end 327.486518 -222.365316)
		(width 0.18288)
		(layer "In2.Cu")
		(net "M_B_CPU0_SB_DQ<18>")
	)
	(segment
		(start 332.562962 -226.265994)
		(end 332.23835 -225.941382)
		(width 0.088646)
		(layer "In2.Cu")
		(net "M_B_CPU0_SB_DQ<18>")
	)
	(segment
		(start 328.711814 -223.590612)
		(end 328.485246 -223.364044)
		(width 0.18288)
		(layer "In2.Cu")
		(net "M_B_CPU0_SB_DQ<18>")
	)
	(segment
		(start 306.045616 -211.929472)
		(end 304.85461 -211.929472)
		(width 0.18288)
		(layer "In2.Cu")
		(net "M_B_CPU0_SB_DQ<18>")
	)
	(segment
		(start 334.77454 -228.948488)
		(end 334.488536 -228.783388)
		(width 0.088646)
		(layer "In2.Cu")
		(net "M_B_CPU0_SB_DQ<18>")
	)
	(segment
		(start 300.079156 -213.092792)
		(end 299.60316 -212.616796)
		(width 0.18288)
		(layer "In2.Cu")
		(net "M_B_CPU0_SB_DQ<18>")
	)
	(segment
		(start 313.882278 -212.236304)
		(end 313.569858 -211.923884)
		(width 0.18288)
		(layer "In2.Cu")
		(net "M_B_CPU0_SB_DQ<18>")
	)
	(segment
		(start 309.77205 -212.064092)
		(end 309.51297 -212.323172)
		(width 0.18288)
		(layer "In2.Cu")
		(net "M_B_CPU0_SB_DQ<18>")
	)
	(segment
		(start 324.490334 -219.096336)
		(end 324.666102 -218.920822)
		(width 0.18288)
		(layer "In2.Cu")
		(net "M_B_CPU0_SB_DQ<18>")
	)
	(segment
		(start 337.808316 -229.253796)
		(end 337.606132 -229.169214)
		(width 0.088646)
		(layer "In2.Cu")
		(net "M_B_CPU0_SB_DQ<18>")
	)
	(segment
		(start 324.666102 -218.648026)
		(end 324.439534 -218.421458)
		(width 0.18288)
		(layer "In2.Cu")
		(net "M_B_CPU0_SB_DQ<18>")
	)
	(segment
		(start 307.30571 -212.109812)
		(end 307.16855 -212.246972)
		(width 0.18288)
		(layer "In2.Cu")
		(net "M_B_CPU0_SB_DQ<18>")
	)
	(segment
		(start 323.16801 -217.42273)
		(end 322.992242 -217.598244)
		(width 0.18288)
		(layer "In2.Cu")
		(net "M_B_CPU0_SB_DQ<18>")
	)
	(segment
		(start 328.485246 -223.091248)
		(end 328.661014 -222.915734)
		(width 0.18288)
		(layer "In2.Cu")
		(net "M_B_CPU0_SB_DQ<18>")
	)
	(segment
		(start 307.967634 -212.109812)
		(end 307.30571 -212.109812)
		(width 0.18288)
		(layer "In2.Cu")
		(net "M_B_CPU0_SB_DQ<18>")
	)
	(segment
		(start 326.48779 -221.366588)
		(end 326.48779 -221.093792)
		(width 0.18288)
		(layer "In2.Cu")
		(net "M_B_CPU0_SB_DQ<18>")
	)
	(segment
		(start 330.431902 -224.413826)
		(end 330.159106 -224.413826)
		(width 0.18288)
		(layer "In2.Cu")
		(net "M_B_CPU0_SB_DQ<18>")
	)
	(segment
		(start 327.662286 -221.64421)
		(end 327.435718 -221.417642)
		(width 0.18288)
		(layer "In2.Cu")
		(net "M_B_CPU0_SB_DQ<18>")
	)
	(segment
		(start 336.842354 -228.945694)
		(end 336.838036 -228.948488)
		(width 0.088646)
		(layer "In2.Cu")
		(net "M_B_CPU0_SB_DQ<18>")
	)
	(segment
		(start 323.667374 -217.922094)
		(end 323.667374 -217.649298)
		(width 0.18288)
		(layer "In2.Cu")
		(net "M_B_CPU0_SB_DQ<18>")
	)
	(segment
		(start 311.273698 -212.064092)
		(end 309.77205 -212.064092)
		(width 0.18288)
		(layer "In2.Cu")
		(net "M_B_CPU0_SB_DQ<18>")
	)
	(segment
		(start 325.165466 -219.420186)
		(end 324.989698 -219.5957)
		(width 0.18288)
		(layer "In2.Cu")
		(net "M_B_CPU0_SB_DQ<18>")
	)
	(segment
		(start 327.486518 -222.09252)
		(end 327.662286 -221.917006)
		(width 0.18288)
		(layer "In2.Cu")
		(net "M_B_CPU0_SB_DQ<18>")
	)
	(segment
		(start 334.018636 -227.969318)
		(end 334.009746 -227.964238)
		(width 0.088646)
		(layer "In2.Cu")
		(net "M_B_CPU0_SB_DQ<18>")
	)
	(segment
		(start 329.483974 -224.089976)
		(end 329.659742 -223.914462)
		(width 0.18288)
		(layer "In2.Cu")
		(net "M_B_CPU0_SB_DQ<18>")
	)
	(arc
		(start 333.831184 -227.64496)
		(mid 333.757268 -227.365458)
		(end 333.554832 -227.159058)
		(width 0.088646)
		(layer "In2.Cu")
		(net "M_B_CPU0_SB_DQ<18>")
	)
	(arc
		(start 333.539846 -227.150422)
		(mid 333.408932 -227.014062)
		(end 333.361284 -226.831144)
		(width 0.088646)
		(layer "In2.Cu")
		(net "M_B_CPU0_SB_DQ<18>")
	)
	(arc
		(start 335.898236 -228.948488)
		(mid 335.617269 -229.024135)
		(end 335.33588 -228.950012)
		(width 0.088646)
		(layer "In2.Cu")
		(net "M_B_CPU0_SB_DQ<18>")
	)
	(arc
		(start 337.212432 -228.948234)
		(mid 337.027738 -228.898133)
		(end 336.842354 -228.945694)
		(width 0.088646)
		(layer "In2.Cu")
		(net "M_B_CPU0_SB_DQ<18>")
	)
	(arc
		(start 337.905598 -229.272846)
		(mid 337.900264 -229.272892)
		(end 337.89493 -229.272846)
		(width 0.088646)
		(layer "In2.Cu")
		(net "M_B_CPU0_SB_DQ<18>")
	)
	(arc
		(start 337.89493 -229.272846)
		(mid 337.850758 -229.267257)
		(end 337.808316 -229.253796)
		(width 0.088646)
		(layer "In2.Cu")
		(net "M_B_CPU0_SB_DQ<18>")
	)
	(arc
		(start 336.272378 -228.948488)
		(mid 336.085324 -228.898438)
		(end 335.898236 -228.948488)
		(width 0.088646)
		(layer "In2.Cu")
		(net "M_B_CPU0_SB_DQ<18>")
	)
	(arc
		(start 334.958436 -228.948488)
		(mid 334.866488 -228.973125)
		(end 334.77454 -228.948488)
		(width 0.088646)
		(layer "In2.Cu")
		(net "M_B_CPU0_SB_DQ<18>")
	)
	(arc
		(start 334.488282 -228.783134)
		(mid 334.351237 -228.646174)
		(end 334.301084 -228.45903)
		(width 0.088646)
		(layer "In2.Cu")
		(net "M_B_CPU0_SB_DQ<18>")
	)
	(arc
		(start 335.332832 -228.948488)
		(mid 335.145634 -228.898311)
		(end 334.958436 -228.948488)
		(width 0.088646)
		(layer "In2.Cu")
		(net "M_B_CPU0_SB_DQ<18>")
	)
	(arc
		(start 336.838036 -228.948488)
		(mid 336.555334 -229.02423)
		(end 336.272632 -228.948488)
		(width 0.088646)
		(layer "In2.Cu")
		(net "M_B_CPU0_SB_DQ<18>")
	)
	(arc
		(start 333.361284 -226.831144)
		(mid 333.289049 -226.55462)
		(end 333.090774 -226.348798)
		(width 0.088646)
		(layer "In2.Cu")
		(net "M_B_CPU0_SB_DQ<18>")
	)
	(arc
		(start 334.301084 -228.440488)
		(mid 334.220922 -228.168299)
		(end 334.018636 -227.969318)
		(width 0.088646)
		(layer "In2.Cu")
		(net "M_B_CPU0_SB_DQ<18>")
	)
	(arc
		(start 334.009746 -227.964238)
		(mid 333.878832 -227.827878)
		(end 333.831184 -227.64496)
		(width 0.088646)
		(layer "In2.Cu")
		(net "M_B_CPU0_SB_DQ<18>")
	)
	(arc
		(start 333.078582 -226.341686)
		(mid 332.942213 -226.285244)
		(end 332.79588 -226.265994)
		(width 0.088646)
		(layer "In2.Cu")
		(net "M_B_CPU0_SB_DQ<18>")
	)
	(arc
		(start 337.606132 -229.169214)
		(mid 337.565747 -229.150809)
		(end 337.52663 -229.129844)
		(width 0.088646)
		(layer "In2.Cu")
		(net "M_B_CPU0_SB_DQ<18>")
	)
	(segment
		(start 291.225986 -211.341716)
		(end 289.240468 -211.341716)
		(width 0.1016)
		(layer "F.Cu")
		(net "M_B_CPU0_SB_DQ<17>")
	)
	(segment
		(start 291.556694 -211.341716)
		(end 291.225986 -211.341716)
		(width 0.101854)
		(layer "F.Cu")
		(net "M_B_CPU0_SB_DQ<17>")
	)
	(segment
		(start 293.799514 -211.766658)
		(end 292.160198 -211.766658)
		(width 0.20066)
		(layer "F.Cu")
		(net "M_B_CPU0_SB_DQ<17>")
	)
	(segment
		(start 287.801304 -211.977986)
		(end 287.589976 -211.766658)
		(width 0.20066)
		(layer "F.Cu")
		(net "M_B_CPU0_SB_DQ<17>")
	)
	(segment
		(start 294.904414 -211.766658)
		(end 293.799514 -211.766658)
		(width 0.20066)
		(layer "F.Cu")
		(net "M_B_CPU0_SB_DQ<17>")
	)
	(segment
		(start 336.555334 -228.459284)
		(end 336.55508 -228.45903)
		(width 0.20066)
		(layer "F.Cu")
		(net "M_B_CPU0_SB_DQ<17>")
	)
	(segment
		(start 288.46018 -211.495386)
		(end 288.46018 -211.823554)
		(width 0.20066)
		(layer "F.Cu")
		(net "M_B_CPU0_SB_DQ<17>")
	)
	(segment
		(start 288.46018 -211.823554)
		(end 288.305748 -211.977986)
		(width 0.20066)
		(layer "F.Cu")
		(net "M_B_CPU0_SB_DQ<17>")
	)
	(segment
		(start 292.160198 -211.766658)
		(end 291.735256 -211.341716)
		(width 0.20066)
		(layer "F.Cu")
		(net "M_B_CPU0_SB_DQ<17>")
	)
	(segment
		(start 289.240468 -211.341716)
		(end 289.231578 -211.332826)
		(width 0.1016)
		(layer "F.Cu")
		(net "M_B_CPU0_SB_DQ<17>")
	)
	(segment
		(start 288.62274 -211.332826)
		(end 288.46018 -211.495386)
		(width 0.20066)
		(layer "F.Cu")
		(net "M_B_CPU0_SB_DQ<17>")
	)
	(segment
		(start 289.231578 -211.332826)
		(end 288.62274 -211.332826)
		(width 0.20066)
		(layer "F.Cu")
		(net "M_B_CPU0_SB_DQ<17>")
	)
	(segment
		(start 291.735256 -211.341716)
		(end 291.556694 -211.341716)
		(width 0.20066)
		(layer "F.Cu")
		(net "M_B_CPU0_SB_DQ<17>")
	)
	(segment
		(start 288.305748 -211.977986)
		(end 287.801304 -211.977986)
		(width 0.20066)
		(layer "F.Cu")
		(net "M_B_CPU0_SB_DQ<17>")
	)
	(segment
		(start 287.589976 -211.766658)
		(end 286.255714 -211.766658)
		(width 0.20066)
		(layer "F.Cu")
		(net "M_B_CPU0_SB_DQ<17>")
	)
	(segment
		(start 336.555334 -228.99497)
		(end 336.555334 -228.459284)
		(width 0.20066)
		(layer "F.Cu")
		(net "M_B_CPU0_SB_DQ<17>")
	)
	(segment
		(start 307.211222 -211.327492)
		(end 303.608994 -211.327492)
		(width 0.18288)
		(layer "In2.Cu")
		(net "M_B_CPU0_SB_DQ<17>")
	)
	(segment
		(start 333.461868 -225.69805)
		(end 333.452978 -225.69297)
		(width 0.088646)
		(layer "In2.Cu")
		(net "M_B_CPU0_SB_DQ<17>")
	)
	(segment
		(start 331.914754 -225.142806)
		(end 331.549756 -225.142806)
		(width 0.18288)
		(layer "In2.Cu")
		(net "M_B_CPU0_SB_DQ<17>")
	)
	(segment
		(start 296.819066 -210.688428)
		(end 296.626026 -210.495388)
		(width 0.18288)
		(layer "In2.Cu")
		(net "M_B_CPU0_SB_DQ<17>")
	)
	(segment
		(start 309.580026 -211.144358)
		(end 308.253638 -211.144358)
		(width 0.18288)
		(layer "In2.Cu")
		(net "M_B_CPU0_SB_DQ<17>")
	)
	(segment
		(start 332.32598 -225.54946)
		(end 332.321408 -225.54946)
		(width 0.088646)
		(layer "In2.Cu")
		(net "M_B_CPU0_SB_DQ<17>")
	)
	(segment
		(start 299.190918 -212.191854)
		(end 298.501308 -212.191854)
		(width 0.18288)
		(layer "In2.Cu")
		(net "M_B_CPU0_SB_DQ<17>")
	)
	(segment
		(start 296.158666 -210.495388)
		(end 295.965626 -210.688428)
		(width 0.18288)
		(layer "In2.Cu")
		(net "M_B_CPU0_SB_DQ<17>")
	)
	(segment
		(start 334.58023 -227.659184)
		(end 334.58023 -227.636324)
		(width 0.088646)
		(layer "In2.Cu")
		(net "M_B_CPU0_SB_DQ<17>")
	)
	(segment
		(start 314.673742 -211.589366)
		(end 314.41771 -211.333334)
		(width 0.18288)
		(layer "In2.Cu")
		(net "M_B_CPU0_SB_DQ<17>")
	)
	(segment
		(start 297.012106 -211.344002)
		(end 296.819066 -211.150962)
		(width 0.18288)
		(layer "In2.Cu")
		(net "M_B_CPU0_SB_DQ<17>")
	)
	(segment
		(start 314.41771 -211.333334)
		(end 311.395872 -211.333334)
		(width 0.18288)
		(layer "In2.Cu")
		(net "M_B_CPU0_SB_DQ<17>")
	)
	(segment
		(start 295.965626 -211.885276)
		(end 295.772332 -212.07857)
		(width 0.18288)
		(layer "In2.Cu")
		(net "M_B_CPU0_SB_DQ<17>")
	)
	(segment
		(start 298.310046 -211.537042)
		(end 298.117006 -211.344002)
		(width 0.18288)
		(layer "In2.Cu")
		(net "M_B_CPU0_SB_DQ<17>")
	)
	(segment
		(start 316.017656 -211.396326)
		(end 316.017656 -210.891628)
		(width 0.18288)
		(layer "In2.Cu")
		(net "M_B_CPU0_SB_DQ<17>")
	)
	(segment
		(start 315.311536 -211.396326)
		(end 315.118496 -211.589366)
		(width 0.18288)
		(layer "In2.Cu")
		(net "M_B_CPU0_SB_DQ<17>")
	)
	(segment
		(start 295.965626 -210.688428)
		(end 295.965626 -211.885276)
		(width 0.18288)
		(layer "In2.Cu")
		(net "M_B_CPU0_SB_DQ<17>")
	)
	(segment
		(start 315.824616 -210.698588)
		(end 315.504576 -210.698588)
		(width 0.18288)
		(layer "In2.Cu")
		(net "M_B_CPU0_SB_DQ<17>")
	)
	(segment
		(start 335.830672 -228.767132)
		(end 335.802732 -228.783388)
		(width 0.088646)
		(layer "In2.Cu")
		(net "M_B_CPU0_SB_DQ<17>")
	)
	(segment
		(start 300.093634 -211.938362)
		(end 299.44441 -211.938362)
		(width 0.18288)
		(layer "In2.Cu")
		(net "M_B_CPU0_SB_DQ<17>")
	)
	(segment
		(start 309.97906 -211.543392)
		(end 309.580026 -211.144358)
		(width 0.18288)
		(layer "In2.Cu")
		(net "M_B_CPU0_SB_DQ<17>")
	)
	(segment
		(start 298.117006 -211.344002)
		(end 297.012106 -211.344002)
		(width 0.18288)
		(layer "In2.Cu")
		(net "M_B_CPU0_SB_DQ<17>")
	)
	(segment
		(start 335.428336 -228.783388)
		(end 335.142332 -228.618034)
		(width 0.088646)
		(layer "In2.Cu")
		(net "M_B_CPU0_SB_DQ<17>")
	)
	(segment
		(start 298.310046 -212.000592)
		(end 298.310046 -211.537042)
		(width 0.18288)
		(layer "In2.Cu")
		(net "M_B_CPU0_SB_DQ<17>")
	)
	(segment
		(start 333.078582 -225.69297)
		(end 333.06385 -225.701606)
		(width 0.088646)
		(layer "In2.Cu")
		(net "M_B_CPU0_SB_DQ<17>")
	)
	(segment
		(start 311.185814 -211.543392)
		(end 309.97906 -211.543392)
		(width 0.18288)
		(layer "In2.Cu")
		(net "M_B_CPU0_SB_DQ<17>")
	)
	(segment
		(start 334.862932 -228.134926)
		(end 334.862932 -228.134672)
		(width 0.088646)
		(layer "In2.Cu")
		(net "M_B_CPU0_SB_DQ<17>")
	)
	(segment
		(start 336.55508 -228.45903)
		(end 335.830672 -228.767132)
		(width 0.088646)
		(layer "In2.Cu")
		(net "M_B_CPU0_SB_DQ<17>")
	)
	(segment
		(start 296.626026 -210.495388)
		(end 296.158666 -210.495388)
		(width 0.18288)
		(layer "In2.Cu")
		(net "M_B_CPU0_SB_DQ<17>")
	)
	(segment
		(start 295.216326 -212.07857)
		(end 294.904414 -211.766658)
		(width 0.18288)
		(layer "In2.Cu")
		(net "M_B_CPU0_SB_DQ<17>")
	)
	(segment
		(start 316.017656 -210.891628)
		(end 315.824616 -210.698588)
		(width 0.18288)
		(layer "In2.Cu")
		(net "M_B_CPU0_SB_DQ<17>")
	)
	(segment
		(start 322.51142 -216.669366)
		(end 317.43142 -211.589366)
		(width 0.18288)
		(layer "In2.Cu")
		(net "M_B_CPU0_SB_DQ<17>")
	)
	(segment
		(start 295.772332 -212.07857)
		(end 295.216326 -212.07857)
		(width 0.18288)
		(layer "In2.Cu")
		(net "M_B_CPU0_SB_DQ<17>")
	)
	(segment
		(start 331.549756 -225.142806)
		(end 331.356462 -224.949512)
		(width 0.18288)
		(layer "In2.Cu")
		(net "M_B_CPU0_SB_DQ<17>")
	)
	(segment
		(start 332.032102 -225.260154)
		(end 331.914754 -225.142806)
		(width 0.18288)
		(layer "In2.Cu")
		(net "M_B_CPU0_SB_DQ<17>")
	)
	(segment
		(start 299.44441 -211.938362)
		(end 299.190918 -212.191854)
		(width 0.18288)
		(layer "In2.Cu")
		(net "M_B_CPU0_SB_DQ<17>")
	)
	(segment
		(start 323.458078 -216.669366)
		(end 322.51142 -216.669366)
		(width 0.18288)
		(layer "In2.Cu")
		(net "M_B_CPU0_SB_DQ<17>")
	)
	(segment
		(start 331.356462 -224.583244)
		(end 323.458078 -216.669366)
		(width 0.18288)
		(layer "In2.Cu")
		(net "M_B_CPU0_SB_DQ<17>")
	)
	(segment
		(start 316.210696 -211.589366)
		(end 316.017656 -211.396326)
		(width 0.18288)
		(layer "In2.Cu")
		(net "M_B_CPU0_SB_DQ<17>")
	)
	(segment
		(start 331.356462 -224.949512)
		(end 331.356462 -224.583244)
		(width 0.18288)
		(layer "In2.Cu")
		(net "M_B_CPU0_SB_DQ<17>")
	)
	(segment
		(start 298.501308 -212.191854)
		(end 298.310046 -212.000592)
		(width 0.18288)
		(layer "In2.Cu")
		(net "M_B_CPU0_SB_DQ<17>")
	)
	(segment
		(start 315.118496 -211.589366)
		(end 314.673742 -211.589366)
		(width 0.18288)
		(layer "In2.Cu")
		(net "M_B_CPU0_SB_DQ<17>")
	)
	(segment
		(start 302.755554 -212.180932)
		(end 300.336204 -212.180932)
		(width 0.18288)
		(layer "In2.Cu")
		(net "M_B_CPU0_SB_DQ<17>")
	)
	(segment
		(start 315.311536 -210.891628)
		(end 315.311536 -211.396326)
		(width 0.18288)
		(layer "In2.Cu")
		(net "M_B_CPU0_SB_DQ<17>")
	)
	(segment
		(start 303.608994 -211.327492)
		(end 302.755554 -212.180932)
		(width 0.18288)
		(layer "In2.Cu")
		(net "M_B_CPU0_SB_DQ<17>")
	)
	(segment
		(start 296.819066 -211.150962)
		(end 296.819066 -210.688428)
		(width 0.18288)
		(layer "In2.Cu")
		(net "M_B_CPU0_SB_DQ<17>")
	)
	(segment
		(start 334.11033 -226.831144)
		(end 334.11033 -226.822508)
		(width 0.088646)
		(layer "In2.Cu")
		(net "M_B_CPU0_SB_DQ<17>")
	)
	(segment
		(start 317.43142 -211.589366)
		(end 316.210696 -211.589366)
		(width 0.18288)
		(layer "In2.Cu")
		(net "M_B_CPU0_SB_DQ<17>")
	)
	(segment
		(start 307.89372 -211.504276)
		(end 307.388006 -211.504276)
		(width 0.18288)
		(layer "In2.Cu")
		(net "M_B_CPU0_SB_DQ<17>")
	)
	(segment
		(start 333.923132 -226.506786)
		(end 333.91094 -226.499674)
		(width 0.088646)
		(layer "In2.Cu")
		(net "M_B_CPU0_SB_DQ<17>")
	)
	(segment
		(start 300.336204 -212.180932)
		(end 300.093634 -211.938362)
		(width 0.18288)
		(layer "In2.Cu")
		(net "M_B_CPU0_SB_DQ<17>")
	)
	(segment
		(start 307.388006 -211.504276)
		(end 307.211222 -211.327492)
		(width 0.18288)
		(layer "In2.Cu")
		(net "M_B_CPU0_SB_DQ<17>")
	)
	(segment
		(start 311.395872 -211.333334)
		(end 311.185814 -211.543392)
		(width 0.18288)
		(layer "In2.Cu")
		(net "M_B_CPU0_SB_DQ<17>")
	)
	(segment
		(start 334.393032 -227.320602)
		(end 334.386936 -227.317046)
		(width 0.088646)
		(layer "In2.Cu")
		(net "M_B_CPU0_SB_DQ<17>")
	)
	(segment
		(start 315.504576 -210.698588)
		(end 315.311536 -210.891628)
		(width 0.18288)
		(layer "In2.Cu")
		(net "M_B_CPU0_SB_DQ<17>")
	)
	(segment
		(start 308.253638 -211.144358)
		(end 307.89372 -211.504276)
		(width 0.18288)
		(layer "In2.Cu")
		(net "M_B_CPU0_SB_DQ<17>")
	)
	(segment
		(start 332.321408 -225.54946)
		(end 332.032102 -225.260154)
		(width 0.088646)
		(layer "In2.Cu")
		(net "M_B_CPU0_SB_DQ<17>")
	)
	(arc
		(start 335.142332 -228.618034)
		(mid 335.075002 -228.550876)
		(end 335.050384 -228.45903)
		(width 0.088646)
		(layer "In2.Cu")
		(net "M_B_CPU0_SB_DQ<17>")
	)
	(arc
		(start 334.862932 -228.134672)
		(mid 334.659451 -227.933868)
		(end 334.58023 -227.659184)
		(width 0.088646)
		(layer "In2.Cu")
		(net "M_B_CPU0_SB_DQ<17>")
	)
	(arc
		(start 333.91094 -226.499674)
		(mid 333.712712 -226.293826)
		(end 333.64043 -226.017328)
		(width 0.088646)
		(layer "In2.Cu")
		(net "M_B_CPU0_SB_DQ<17>")
	)
	(arc
		(start 333.452978 -225.69297)
		(mid 333.26578 -225.642827)
		(end 333.078582 -225.69297)
		(width 0.088646)
		(layer "In2.Cu")
		(net "M_B_CPU0_SB_DQ<17>")
	)
	(arc
		(start 334.11033 -226.822508)
		(mid 334.05806 -226.640143)
		(end 333.923132 -226.506786)
		(width 0.088646)
		(layer "In2.Cu")
		(net "M_B_CPU0_SB_DQ<17>")
	)
	(arc
		(start 334.386936 -227.317046)
		(mid 334.184349 -227.110695)
		(end 334.11033 -226.831144)
		(width 0.088646)
		(layer "In2.Cu")
		(net "M_B_CPU0_SB_DQ<17>")
	)
	(arc
		(start 333.06385 -225.701606)
		(mid 332.787409 -225.768772)
		(end 332.513178 -225.69297)
		(width 0.088646)
		(layer "In2.Cu")
		(net "M_B_CPU0_SB_DQ<17>")
	)
	(arc
		(start 335.802732 -228.783388)
		(mid 335.615534 -228.833565)
		(end 335.428336 -228.783388)
		(width 0.088646)
		(layer "In2.Cu")
		(net "M_B_CPU0_SB_DQ<17>")
	)
	(arc
		(start 332.513178 -225.69297)
		(mid 332.414866 -225.627363)
		(end 332.32598 -225.54946)
		(width 0.088646)
		(layer "In2.Cu")
		(net "M_B_CPU0_SB_DQ<17>")
	)
	(arc
		(start 334.58023 -227.636324)
		(mid 334.52796 -227.453959)
		(end 334.393032 -227.320602)
		(width 0.088646)
		(layer "In2.Cu")
		(net "M_B_CPU0_SB_DQ<17>")
	)
	(arc
		(start 333.64043 -226.017328)
		(mid 333.592751 -225.834428)
		(end 333.461868 -225.69805)
		(width 0.088646)
		(layer "In2.Cu")
		(net "M_B_CPU0_SB_DQ<17>")
	)
	(arc
		(start 335.050384 -228.45903)
		(mid 335.000144 -228.271829)
		(end 334.862932 -228.134926)
		(width 0.088646)
		(layer "In2.Cu")
		(net "M_B_CPU0_SB_DQ<17>")
	)
	(segment
		(start 288.28746 -213.70544)
		(end 287.828736 -213.70544)
		(width 0.20066)
		(layer "F.Cu")
		(net "M_B_CPU0_SB_DQ<16>")
	)
	(segment
		(start 294.904414 -213.46668)
		(end 293.799514 -213.46668)
		(width 0.20066)
		(layer "F.Cu")
		(net "M_B_CPU0_SB_DQ<16>")
	)
	(segment
		(start 289.239706 -213.041738)
		(end 289.231578 -213.03361)
		(width 0.101854)
		(layer "F.Cu")
		(net "M_B_CPU0_SB_DQ<16>")
	)
	(segment
		(start 287.828736 -213.70544)
		(end 287.589976 -213.46668)
		(width 0.20066)
		(layer "F.Cu")
		(net "M_B_CPU0_SB_DQ<16>")
	)
	(segment
		(start 287.589976 -213.46668)
		(end 286.255714 -213.46668)
		(width 0.20066)
		(layer "F.Cu")
		(net "M_B_CPU0_SB_DQ<16>")
	)
	(segment
		(start 337.025234 -229.808532)
		(end 337.025234 -229.272846)
		(width 0.20066)
		(layer "F.Cu")
		(net "M_B_CPU0_SB_DQ<16>")
	)
	(segment
		(start 289.231578 -213.03361)
		(end 288.66973 -213.03361)
		(width 0.20066)
		(layer "F.Cu")
		(net "M_B_CPU0_SB_DQ<16>")
	)
	(segment
		(start 293.799514 -213.46668)
		(end 292.430454 -213.46668)
		(width 0.20066)
		(layer "F.Cu")
		(net "M_B_CPU0_SB_DQ<16>")
	)
	(segment
		(start 289.48761 -213.041738)
		(end 289.239706 -213.041738)
		(width 0.101854)
		(layer "F.Cu")
		(net "M_B_CPU0_SB_DQ<16>")
	)
	(segment
		(start 337.02498 -229.808786)
		(end 337.025234 -229.808532)
		(width 0.20066)
		(layer "F.Cu")
		(net "M_B_CPU0_SB_DQ<16>")
	)
	(segment
		(start 292.430454 -213.46668)
		(end 292.005512 -213.041738)
		(width 0.20066)
		(layer "F.Cu")
		(net "M_B_CPU0_SB_DQ<16>")
	)
	(segment
		(start 288.46018 -213.53272)
		(end 288.28746 -213.70544)
		(width 0.20066)
		(layer "F.Cu")
		(net "M_B_CPU0_SB_DQ<16>")
	)
	(segment
		(start 288.66973 -213.03361)
		(end 288.46018 -213.24316)
		(width 0.20066)
		(layer "F.Cu")
		(net "M_B_CPU0_SB_DQ<16>")
	)
	(segment
		(start 291.556694 -213.041738)
		(end 289.48761 -213.041738)
		(width 0.1016)
		(layer "F.Cu")
		(net "M_B_CPU0_SB_DQ<16>")
	)
	(segment
		(start 288.46018 -213.24316)
		(end 288.46018 -213.53272)
		(width 0.20066)
		(layer "F.Cu")
		(net "M_B_CPU0_SB_DQ<16>")
	)
	(segment
		(start 292.005512 -213.041738)
		(end 291.556694 -213.041738)
		(width 0.20066)
		(layer "F.Cu")
		(net "M_B_CPU0_SB_DQ<16>")
	)
	(segment
		(start 307.618384 -213.181184)
		(end 307.19903 -212.76183)
		(width 0.18288)
		(layer "In2.Cu")
		(net "M_B_CPU0_SB_DQ<16>")
	)
	(segment
		(start 305.612546 -213.672674)
		(end 305.038506 -213.672674)
		(width 0.18288)
		(layer "In2.Cu")
		(net "M_B_CPU0_SB_DQ<16>")
	)
	(segment
		(start 304.411634 -212.860382)
		(end 303.59604 -212.860382)
		(width 0.18288)
		(layer "In2.Cu")
		(net "M_B_CPU0_SB_DQ<16>")
	)
	(segment
		(start 333.171038 -226.831144)
		(end 333.17053 -226.831144)
		(width 0.088646)
		(layer "In2.Cu")
		(net "M_B_CPU0_SB_DQ<16>")
	)
	(segment
		(start 295.587166 -214.22487)
		(end 295.394126 -214.03183)
		(width 0.18288)
		(layer "In2.Cu")
		(net "M_B_CPU0_SB_DQ<16>")
	)
	(segment
		(start 314.711842 -212.644482)
		(end 314.332366 -213.023958)
		(width 0.18288)
		(layer "In2.Cu")
		(net "M_B_CPU0_SB_DQ<16>")
	)
	(segment
		(start 334.110584 -228.459284)
		(end 334.110584 -228.45903)
		(width 0.088646)
		(layer "In2.Cu")
		(net "M_B_CPU0_SB_DQ<16>")
	)
	(segment
		(start 303.59604 -212.860382)
		(end 302.585628 -213.870794)
		(width 0.18288)
		(layer "In2.Cu")
		(net "M_B_CPU0_SB_DQ<16>")
	)
	(segment
		(start 314.332366 -213.023958)
		(end 311.064148 -213.023958)
		(width 0.18288)
		(layer "In2.Cu")
		(net "M_B_CPU0_SB_DQ<16>")
	)
	(segment
		(start 334.959198 -229.59441)
		(end 334.956404 -229.592632)
		(width 0.088646)
		(layer "In2.Cu")
		(net "M_B_CPU0_SB_DQ<16>")
	)
	(segment
		(start 332.076806 -226.458272)
		(end 330.844144 -226.458272)
		(width 0.18288)
		(layer "In2.Cu")
		(net "M_B_CPU0_SB_DQ<16>")
	)
	(segment
		(start 297.302174 -213.020656)
		(end 296.323766 -213.020656)
		(width 0.18288)
		(layer "In2.Cu")
		(net "M_B_CPU0_SB_DQ<16>")
	)
	(segment
		(start 304.845466 -213.294214)
		(end 304.411634 -212.860382)
		(width 0.18288)
		(layer "In2.Cu")
		(net "M_B_CPU0_SB_DQ<16>")
	)
	(segment
		(start 298.34586 -213.770464)
		(end 298.18584 -213.930484)
		(width 0.18288)
		(layer "In2.Cu")
		(net "M_B_CPU0_SB_DQ<16>")
	)
	(segment
		(start 334.679036 -229.113842)
		(end 334.393032 -228.948488)
		(width 0.088646)
		(layer "In2.Cu")
		(net "M_B_CPU0_SB_DQ<16>")
	)
	(segment
		(start 310.180736 -213.53145)
		(end 309.691278 -213.041992)
		(width 0.18288)
		(layer "In2.Cu")
		(net "M_B_CPU0_SB_DQ<16>")
	)
	(segment
		(start 308.032404 -213.041992)
		(end 307.893212 -213.181184)
		(width 0.18288)
		(layer "In2.Cu")
		(net "M_B_CPU0_SB_DQ<16>")
	)
	(segment
		(start 330.844144 -226.458272)
		(end 317.030354 -212.644482)
		(width 0.18288)
		(layer "In2.Cu")
		(net "M_B_CPU0_SB_DQ<16>")
	)
	(segment
		(start 296.130726 -213.213696)
		(end 296.130726 -214.03183)
		(width 0.18288)
		(layer "In2.Cu")
		(net "M_B_CPU0_SB_DQ<16>")
	)
	(segment
		(start 307.893212 -213.181184)
		(end 307.618384 -213.181184)
		(width 0.18288)
		(layer "In2.Cu")
		(net "M_B_CPU0_SB_DQ<16>")
	)
	(segment
		(start 335.333086 -229.597204)
		(end 335.332832 -229.597204)
		(width 0.088646)
		(layer "In2.Cu")
		(net "M_B_CPU0_SB_DQ<16>")
	)
	(segment
		(start 297.494452 -213.770464)
		(end 297.494452 -213.212934)
		(width 0.18288)
		(layer "In2.Cu")
		(net "M_B_CPU0_SB_DQ<16>")
	)
	(segment
		(start 295.394126 -214.03183)
		(end 295.394126 -213.65337)
		(width 0.18288)
		(layer "In2.Cu")
		(net "M_B_CPU0_SB_DQ<16>")
	)
	(segment
		(start 306.592986 -212.76183)
		(end 306.311046 -213.04377)
		(width 0.18288)
		(layer "In2.Cu")
		(net "M_B_CPU0_SB_DQ<16>")
	)
	(segment
		(start 295.394126 -213.65337)
		(end 295.207436 -213.46668)
		(width 0.18288)
		(layer "In2.Cu")
		(net "M_B_CPU0_SB_DQ<16>")
	)
	(segment
		(start 295.207436 -213.46668)
		(end 294.904414 -213.46668)
		(width 0.18288)
		(layer "In2.Cu")
		(net "M_B_CPU0_SB_DQ<16>")
	)
	(segment
		(start 333.461868 -227.325682)
		(end 333.446882 -227.317046)
		(width 0.088646)
		(layer "In2.Cu")
		(net "M_B_CPU0_SB_DQ<16>")
	)
	(segment
		(start 305.805586 -213.479634)
		(end 305.612546 -213.672674)
		(width 0.18288)
		(layer "In2.Cu")
		(net "M_B_CPU0_SB_DQ<16>")
	)
	(segment
		(start 332.79588 -226.456494)
		(end 332.078584 -226.456494)
		(width 0.088646)
		(layer "In2.Cu")
		(net "M_B_CPU0_SB_DQ<16>")
	)
	(segment
		(start 297.654472 -213.930484)
		(end 297.494452 -213.770464)
		(width 0.18288)
		(layer "In2.Cu")
		(net "M_B_CPU0_SB_DQ<16>")
	)
	(segment
		(start 337.025234 -229.272846)
		(end 337.02498 -229.272846)
		(width 0.088646)
		(layer "In2.Cu")
		(net "M_B_CPU0_SB_DQ<16>")
	)
	(segment
		(start 302.585628 -213.870794)
		(end 300.013624 -213.870794)
		(width 0.18288)
		(layer "In2.Cu")
		(net "M_B_CPU0_SB_DQ<16>")
	)
	(segment
		(start 295.937686 -214.22487)
		(end 295.587166 -214.22487)
		(width 0.18288)
		(layer "In2.Cu")
		(net "M_B_CPU0_SB_DQ<16>")
	)
	(segment
		(start 299.184568 -213.041738)
		(end 298.506388 -213.041738)
		(width 0.18288)
		(layer "In2.Cu")
		(net "M_B_CPU0_SB_DQ<16>")
	)
	(segment
		(start 334.960722 -229.595172)
		(end 334.959198 -229.59441)
		(width 0.088646)
		(layer "In2.Cu")
		(net "M_B_CPU0_SB_DQ<16>")
	)
	(segment
		(start 336.669888 -229.368096)
		(end 336.272632 -229.597204)
		(width 0.088646)
		(layer "In2.Cu")
		(net "M_B_CPU0_SB_DQ<16>")
	)
	(segment
		(start 304.845466 -213.479634)
		(end 304.845466 -213.294214)
		(width 0.18288)
		(layer "In2.Cu")
		(net "M_B_CPU0_SB_DQ<16>")
	)
	(segment
		(start 298.506388 -213.041738)
		(end 298.34586 -213.202266)
		(width 0.18288)
		(layer "In2.Cu")
		(net "M_B_CPU0_SB_DQ<16>")
	)
	(segment
		(start 333.64043 -227.65258)
		(end 333.64043 -227.64496)
		(width 0.088646)
		(layer "In2.Cu")
		(net "M_B_CPU0_SB_DQ<16>")
	)
	(segment
		(start 298.34586 -213.202266)
		(end 298.34586 -213.770464)
		(width 0.18288)
		(layer "In2.Cu")
		(net "M_B_CPU0_SB_DQ<16>")
	)
	(segment
		(start 333.442818 -227.31476)
		(end 333.443072 -227.314252)
		(width 0.088646)
		(layer "In2.Cu")
		(net "M_B_CPU0_SB_DQ<16>")
	)
	(segment
		(start 305.805586 -213.23681)
		(end 305.805586 -213.479634)
		(width 0.18288)
		(layer "In2.Cu")
		(net "M_B_CPU0_SB_DQ<16>")
	)
	(segment
		(start 305.038506 -213.672674)
		(end 304.845466 -213.479634)
		(width 0.18288)
		(layer "In2.Cu")
		(net "M_B_CPU0_SB_DQ<16>")
	)
	(segment
		(start 332.078584 -226.456494)
		(end 332.076806 -226.458272)
		(width 0.088646)
		(layer "In2.Cu")
		(net "M_B_CPU0_SB_DQ<16>")
	)
	(segment
		(start 296.130726 -214.03183)
		(end 295.937686 -214.22487)
		(width 0.18288)
		(layer "In2.Cu")
		(net "M_B_CPU0_SB_DQ<16>")
	)
	(segment
		(start 300.013624 -213.870794)
		(end 299.184568 -213.041738)
		(width 0.18288)
		(layer "In2.Cu")
		(net "M_B_CPU0_SB_DQ<16>")
	)
	(segment
		(start 334.956404 -229.592632)
		(end 334.915256 -229.568502)
		(width 0.088646)
		(layer "In2.Cu")
		(net "M_B_CPU0_SB_DQ<16>")
	)
	(segment
		(start 306.311046 -213.04377)
		(end 305.998626 -213.04377)
		(width 0.18288)
		(layer "In2.Cu")
		(net "M_B_CPU0_SB_DQ<16>")
	)
	(segment
		(start 305.998626 -213.04377)
		(end 305.805586 -213.23681)
		(width 0.18288)
		(layer "In2.Cu")
		(net "M_B_CPU0_SB_DQ<16>")
	)
	(segment
		(start 298.18584 -213.930484)
		(end 297.654472 -213.930484)
		(width 0.18288)
		(layer "In2.Cu")
		(net "M_B_CPU0_SB_DQ<16>")
	)
	(segment
		(start 310.556656 -213.53145)
		(end 310.180736 -213.53145)
		(width 0.18288)
		(layer "In2.Cu")
		(net "M_B_CPU0_SB_DQ<16>")
	)
	(segment
		(start 317.030354 -212.644482)
		(end 314.711842 -212.644482)
		(width 0.18288)
		(layer "In2.Cu")
		(net "M_B_CPU0_SB_DQ<16>")
	)
	(segment
		(start 296.323766 -213.020656)
		(end 296.130726 -213.213696)
		(width 0.18288)
		(layer "In2.Cu")
		(net "M_B_CPU0_SB_DQ<16>")
	)
	(segment
		(start 297.494452 -213.212934)
		(end 297.302174 -213.020656)
		(width 0.18288)
		(layer "In2.Cu")
		(net "M_B_CPU0_SB_DQ<16>")
	)
	(segment
		(start 309.691278 -213.041992)
		(end 308.032404 -213.041992)
		(width 0.18288)
		(layer "In2.Cu")
		(net "M_B_CPU0_SB_DQ<16>")
	)
	(segment
		(start 333.932022 -228.139752)
		(end 333.923132 -228.134672)
		(width 0.088646)
		(layer "In2.Cu")
		(net "M_B_CPU0_SB_DQ<16>")
	)
	(segment
		(start 307.19903 -212.76183)
		(end 306.592986 -212.76183)
		(width 0.18288)
		(layer "In2.Cu")
		(net "M_B_CPU0_SB_DQ<16>")
	)
	(segment
		(start 311.064148 -213.023958)
		(end 310.556656 -213.53145)
		(width 0.18288)
		(layer "In2.Cu")
		(net "M_B_CPU0_SB_DQ<16>")
	)
	(arc
		(start 334.770984 -229.272846)
		(mid 334.746336 -229.181017)
		(end 334.679036 -229.113842)
		(width 0.088646)
		(layer "In2.Cu")
		(net "M_B_CPU0_SB_DQ<16>")
	)
	(arc
		(start 334.393032 -228.948488)
		(mid 334.186272 -228.741725)
		(end 334.110584 -228.459284)
		(width 0.088646)
		(layer "In2.Cu")
		(net "M_B_CPU0_SB_DQ<16>")
	)
	(arc
		(start 335.332832 -229.597204)
		(mid 335.14649 -229.646592)
		(end 334.960722 -229.595172)
		(width 0.088646)
		(layer "In2.Cu")
		(net "M_B_CPU0_SB_DQ<16>")
	)
	(arc
		(start 337.02498 -229.272846)
		(mid 336.841162 -229.297097)
		(end 336.669888 -229.368096)
		(width 0.088646)
		(layer "In2.Cu")
		(net "M_B_CPU0_SB_DQ<16>")
	)
	(arc
		(start 333.64043 -227.64496)
		(mid 333.592751 -227.46206)
		(end 333.461868 -227.325682)
		(width 0.088646)
		(layer "In2.Cu")
		(net "M_B_CPU0_SB_DQ<16>")
	)
	(arc
		(start 333.17053 -226.831144)
		(mid 333.060798 -226.566226)
		(end 332.79588 -226.456494)
		(width 0.088646)
		(layer "In2.Cu")
		(net "M_B_CPU0_SB_DQ<16>")
	)
	(arc
		(start 333.923132 -228.134672)
		(mid 333.71806 -227.930993)
		(end 333.64043 -227.65258)
		(width 0.088646)
		(layer "In2.Cu")
		(net "M_B_CPU0_SB_DQ<16>")
	)
	(arc
		(start 335.897982 -229.597204)
		(mid 335.615534 -229.521521)
		(end 335.333086 -229.597204)
		(width 0.088646)
		(layer "In2.Cu")
		(net "M_B_CPU0_SB_DQ<16>")
	)
	(arc
		(start 334.915256 -229.568502)
		(mid 334.808948 -229.437353)
		(end 334.770984 -229.272846)
		(width 0.088646)
		(layer "In2.Cu")
		(net "M_B_CPU0_SB_DQ<16>")
	)
	(arc
		(start 334.110584 -228.45903)
		(mid 334.062905 -228.27613)
		(end 333.932022 -228.139752)
		(width 0.088646)
		(layer "In2.Cu")
		(net "M_B_CPU0_SB_DQ<16>")
	)
	(arc
		(start 336.272632 -229.597204)
		(mid 336.085324 -229.647347)
		(end 335.897982 -229.597204)
		(width 0.088646)
		(layer "In2.Cu")
		(net "M_B_CPU0_SB_DQ<16>")
	)
	(arc
		(start 333.446882 -227.317046)
		(mid 333.444848 -227.315907)
		(end 333.442818 -227.31476)
		(width 0.088646)
		(layer "In2.Cu")
		(net "M_B_CPU0_SB_DQ<16>")
	)
	(arc
		(start 333.443072 -227.314252)
		(mid 333.243688 -227.108372)
		(end 333.171038 -226.831144)
		(width 0.088646)
		(layer "In2.Cu")
		(net "M_B_CPU0_SB_DQ<16>")
	)
	(segment
		(start 295.000426 -214.741506)
		(end 292.927532 -214.741506)
		(width 0.1016)
		(layer "F.Cu")
		(net "M_B_CPU0_SB_DQ<15>")
	)
	(segment
		(start 292.927532 -214.741506)
		(end 292.689534 -214.741506)
		(width 0.101854)
		(layer "F.Cu")
		(net "M_B_CPU0_SB_DQ<15>")
	)
	(segment
		(start 295.693846 -214.592408)
		(end 295.544748 -214.741506)
		(width 0.20066)
		(layer "F.Cu")
		(net "M_B_CPU0_SB_DQ<15>")
	)
	(segment
		(start 295.693846 -214.44077)
		(end 295.693846 -214.592408)
		(width 0.20066)
		(layer "F.Cu")
		(net "M_B_CPU0_SB_DQ<15>")
	)
	(segment
		(start 292.321488 -214.75573)
		(end 292.178994 -214.613236)
		(width 0.20066)
		(layer "F.Cu")
		(net "M_B_CPU0_SB_DQ<15>")
	)
	(segment
		(start 337.965034 -231.436164)
		(end 337.965034 -230.900478)
		(width 0.20066)
		(layer "F.Cu")
		(net "M_B_CPU0_SB_DQ<15>")
	)
	(segment
		(start 299.004482 -214.316564)
		(end 297.899582 -214.316564)
		(width 0.20066)
		(layer "F.Cu")
		(net "M_B_CPU0_SB_DQ<15>")
	)
	(segment
		(start 296.217594 -214.312246)
		(end 295.82237 -214.312246)
		(width 0.20066)
		(layer "F.Cu")
		(net "M_B_CPU0_SB_DQ<15>")
	)
	(segment
		(start 292.178994 -214.613236)
		(end 292.178994 -214.442548)
		(width 0.20066)
		(layer "F.Cu")
		(net "M_B_CPU0_SB_DQ<15>")
	)
	(segment
		(start 337.96478 -231.436418)
		(end 337.965034 -231.436164)
		(width 0.20066)
		(layer "F.Cu")
		(net "M_B_CPU0_SB_DQ<15>")
	)
	(segment
		(start 297.899582 -214.316564)
		(end 297.08348 -214.316564)
		(width 0.20066)
		(layer "F.Cu")
		(net "M_B_CPU0_SB_DQ<15>")
	)
	(segment
		(start 297.08348 -214.316564)
		(end 296.875962 -214.524082)
		(width 0.20066)
		(layer "F.Cu")
		(net "M_B_CPU0_SB_DQ<15>")
	)
	(segment
		(start 292.178994 -214.442548)
		(end 292.05301 -214.316564)
		(width 0.20066)
		(layer "F.Cu")
		(net "M_B_CPU0_SB_DQ<15>")
	)
	(segment
		(start 292.67531 -214.75573)
		(end 292.321488 -214.75573)
		(width 0.20066)
		(layer "F.Cu")
		(net "M_B_CPU0_SB_DQ<15>")
	)
	(segment
		(start 292.05301 -214.316564)
		(end 290.355782 -214.316564)
		(width 0.20066)
		(layer "F.Cu")
		(net "M_B_CPU0_SB_DQ<15>")
	)
	(segment
		(start 295.82237 -214.312246)
		(end 295.693846 -214.44077)
		(width 0.20066)
		(layer "F.Cu")
		(net "M_B_CPU0_SB_DQ<15>")
	)
	(segment
		(start 292.689534 -214.741506)
		(end 292.67531 -214.75573)
		(width 0.101854)
		(layer "F.Cu")
		(net "M_B_CPU0_SB_DQ<15>")
	)
	(segment
		(start 296.42943 -214.524082)
		(end 296.217594 -214.312246)
		(width 0.20066)
		(layer "F.Cu")
		(net "M_B_CPU0_SB_DQ<15>")
	)
	(segment
		(start 296.875962 -214.524082)
		(end 296.42943 -214.524082)
		(width 0.20066)
		(layer "F.Cu")
		(net "M_B_CPU0_SB_DQ<15>")
	)
	(segment
		(start 295.544748 -214.741506)
		(end 295.000426 -214.741506)
		(width 0.20066)
		(layer "F.Cu")
		(net "M_B_CPU0_SB_DQ<15>")
	)
	(segment
		(start 304.517044 -214.773256)
		(end 303.846738 -214.10295)
		(width 0.18288)
		(layer "In2.Cu")
		(net "M_B_CPU0_SB_DQ<15>")
	)
	(segment
		(start 309.15483 -213.84768)
		(end 308.61508 -213.84768)
		(width 0.18288)
		(layer "In2.Cu")
		(net "M_B_CPU0_SB_DQ<15>")
	)
	(segment
		(start 335.428082 -230.41102)
		(end 335.41335 -230.402384)
		(width 0.088646)
		(layer "In2.Cu")
		(net "M_B_CPU0_SB_DQ<15>")
	)
	(segment
		(start 333.507334 -230.379524)
		(end 333.036164 -229.908354)
		(width 0.088646)
		(layer "In2.Cu")
		(net "M_B_CPU0_SB_DQ<15>")
	)
	(segment
		(start 315.591952 -214.023194)
		(end 315.591952 -213.662768)
		(width 0.18288)
		(layer "In2.Cu")
		(net "M_B_CPU0_SB_DQ<15>")
	)
	(segment
		(start 335.802732 -230.41102)
		(end 335.802478 -230.41102)
		(width 0.088646)
		(layer "In2.Cu")
		(net "M_B_CPU0_SB_DQ<15>")
	)
	(segment
		(start 315.784992 -214.216234)
		(end 315.591952 -214.023194)
		(width 0.18288)
		(layer "In2.Cu")
		(net "M_B_CPU0_SB_DQ<15>")
	)
	(segment
		(start 311.427368 -213.906354)
		(end 310.57215 -214.761572)
		(width 0.18288)
		(layer "In2.Cu")
		(net "M_B_CPU0_SB_DQ<15>")
	)
	(segment
		(start 314.692792 -214.216234)
		(end 314.144406 -214.216234)
		(width 0.18288)
		(layer "In2.Cu")
		(net "M_B_CPU0_SB_DQ<15>")
	)
	(segment
		(start 334.488282 -230.41102)
		(end 334.47355 -230.402384)
		(width 0.088646)
		(layer "In2.Cu")
		(net "M_B_CPU0_SB_DQ<15>")
	)
	(segment
		(start 316.491112 -213.561422)
		(end 316.298072 -213.754462)
		(width 0.18288)
		(layer "In2.Cu")
		(net "M_B_CPU0_SB_DQ<15>")
	)
	(segment
		(start 302.846486 -214.745316)
		(end 300.559216 -214.745316)
		(width 0.18288)
		(layer "In2.Cu")
		(net "M_B_CPU0_SB_DQ<15>")
	)
	(segment
		(start 314.885832 -214.023194)
		(end 314.692792 -214.216234)
		(width 0.18288)
		(layer "In2.Cu")
		(net "M_B_CPU0_SB_DQ<15>")
	)
	(segment
		(start 308.61508 -213.84768)
		(end 308.414928 -214.047832)
		(width 0.18288)
		(layer "In2.Cu")
		(net "M_B_CPU0_SB_DQ<15>")
	)
	(segment
		(start 332.895448 -229.767638)
		(end 332.895448 -229.235)
		(width 0.18288)
		(layer "In2.Cu")
		(net "M_B_CPU0_SB_DQ<15>")
	)
	(segment
		(start 309.354982 -214.047832)
		(end 309.15483 -213.84768)
		(width 0.18288)
		(layer "In2.Cu")
		(net "M_B_CPU0_SB_DQ<15>")
	)
	(segment
		(start 309.354982 -214.601552)
		(end 309.354982 -214.047832)
		(width 0.18288)
		(layer "In2.Cu")
		(net "M_B_CPU0_SB_DQ<15>")
	)
	(segment
		(start 314.144406 -214.216234)
		(end 313.834526 -213.906354)
		(width 0.18288)
		(layer "In2.Cu")
		(net "M_B_CPU0_SB_DQ<15>")
	)
	(segment
		(start 307.109114 -213.859364)
		(end 306.789074 -213.859364)
		(width 0.18288)
		(layer "In2.Cu")
		(net "M_B_CPU0_SB_DQ<15>")
	)
	(segment
		(start 299.577252 -214.889334)
		(end 299.004482 -214.316564)
		(width 0.18288)
		(layer "In2.Cu")
		(net "M_B_CPU0_SB_DQ<15>")
	)
	(segment
		(start 303.488852 -214.10295)
		(end 302.846486 -214.745316)
		(width 0.18288)
		(layer "In2.Cu")
		(net "M_B_CPU0_SB_DQ<15>")
	)
	(segment
		(start 315.591952 -213.662768)
		(end 315.398912 -213.469728)
		(width 0.18288)
		(layer "In2.Cu")
		(net "M_B_CPU0_SB_DQ<15>")
	)
	(segment
		(start 306.343812 -214.773256)
		(end 304.517044 -214.773256)
		(width 0.18288)
		(layer "In2.Cu")
		(net "M_B_CPU0_SB_DQ<15>")
	)
	(segment
		(start 306.596034 -214.052404)
		(end 306.596034 -214.521034)
		(width 0.18288)
		(layer "In2.Cu")
		(net "M_B_CPU0_SB_DQ<15>")
	)
	(segment
		(start 333.036164 -229.908354)
		(end 332.895448 -229.767638)
		(width 0.18288)
		(layer "In2.Cu")
		(net "M_B_CPU0_SB_DQ<15>")
	)
	(segment
		(start 300.415198 -214.889334)
		(end 299.577252 -214.889334)
		(width 0.18288)
		(layer "In2.Cu")
		(net "M_B_CPU0_SB_DQ<15>")
	)
	(segment
		(start 315.078872 -213.469728)
		(end 314.885832 -213.662768)
		(width 0.18288)
		(layer "In2.Cu")
		(net "M_B_CPU0_SB_DQ<15>")
	)
	(segment
		(start 306.789074 -213.859364)
		(end 306.596034 -214.052404)
		(width 0.18288)
		(layer "In2.Cu")
		(net "M_B_CPU0_SB_DQ<15>")
	)
	(segment
		(start 316.298072 -214.023194)
		(end 316.105032 -214.216234)
		(width 0.18288)
		(layer "In2.Cu")
		(net "M_B_CPU0_SB_DQ<15>")
	)
	(segment
		(start 308.414928 -214.571326)
		(end 308.229508 -214.756746)
		(width 0.18288)
		(layer "In2.Cu")
		(net "M_B_CPU0_SB_DQ<15>")
	)
	(segment
		(start 331.783436 -228.122988)
		(end 331.363574 -228.122988)
		(width 0.18288)
		(layer "In2.Cu")
		(net "M_B_CPU0_SB_DQ<15>")
	)
	(segment
		(start 331.363574 -228.122988)
		(end 316.802008 -213.561422)
		(width 0.18288)
		(layer "In2.Cu")
		(net "M_B_CPU0_SB_DQ<15>")
	)
	(segment
		(start 303.846738 -214.10295)
		(end 303.488852 -214.10295)
		(width 0.18288)
		(layer "In2.Cu")
		(net "M_B_CPU0_SB_DQ<15>")
	)
	(segment
		(start 316.298072 -213.754462)
		(end 316.298072 -214.023194)
		(width 0.18288)
		(layer "In2.Cu")
		(net "M_B_CPU0_SB_DQ<15>")
	)
	(segment
		(start 306.596034 -214.521034)
		(end 306.343812 -214.773256)
		(width 0.18288)
		(layer "In2.Cu")
		(net "M_B_CPU0_SB_DQ<15>")
	)
	(segment
		(start 300.559216 -214.745316)
		(end 300.415198 -214.889334)
		(width 0.18288)
		(layer "In2.Cu")
		(net "M_B_CPU0_SB_DQ<15>")
	)
	(segment
		(start 308.229508 -214.756746)
		(end 307.495194 -214.756746)
		(width 0.18288)
		(layer "In2.Cu")
		(net "M_B_CPU0_SB_DQ<15>")
	)
	(segment
		(start 309.515002 -214.761572)
		(end 309.354982 -214.601552)
		(width 0.18288)
		(layer "In2.Cu")
		(net "M_B_CPU0_SB_DQ<15>")
	)
	(segment
		(start 308.414928 -214.047832)
		(end 308.414928 -214.571326)
		(width 0.18288)
		(layer "In2.Cu")
		(net "M_B_CPU0_SB_DQ<15>")
	)
	(segment
		(start 314.885832 -213.662768)
		(end 314.885832 -214.023194)
		(width 0.18288)
		(layer "In2.Cu")
		(net "M_B_CPU0_SB_DQ<15>")
	)
	(segment
		(start 336.960718 -230.484426)
		(end 336.641694 -230.484426)
		(width 0.088646)
		(layer "In2.Cu")
		(net "M_B_CPU0_SB_DQ<15>")
	)
	(segment
		(start 316.105032 -214.216234)
		(end 315.784992 -214.216234)
		(width 0.18288)
		(layer "In2.Cu")
		(net "M_B_CPU0_SB_DQ<15>")
	)
	(segment
		(start 307.495194 -214.756746)
		(end 307.302154 -214.563706)
		(width 0.18288)
		(layer "In2.Cu")
		(net "M_B_CPU0_SB_DQ<15>")
	)
	(segment
		(start 313.834526 -213.906354)
		(end 311.427368 -213.906354)
		(width 0.18288)
		(layer "In2.Cu")
		(net "M_B_CPU0_SB_DQ<15>")
	)
	(segment
		(start 307.302154 -214.052404)
		(end 307.109114 -213.859364)
		(width 0.18288)
		(layer "In2.Cu")
		(net "M_B_CPU0_SB_DQ<15>")
	)
	(segment
		(start 310.57215 -214.761572)
		(end 309.515002 -214.761572)
		(width 0.18288)
		(layer "In2.Cu")
		(net "M_B_CPU0_SB_DQ<15>")
	)
	(segment
		(start 315.398912 -213.469728)
		(end 315.078872 -213.469728)
		(width 0.18288)
		(layer "In2.Cu")
		(net "M_B_CPU0_SB_DQ<15>")
	)
	(segment
		(start 307.302154 -214.563706)
		(end 307.302154 -214.052404)
		(width 0.18288)
		(layer "In2.Cu")
		(net "M_B_CPU0_SB_DQ<15>")
	)
	(segment
		(start 332.895448 -229.235)
		(end 331.783436 -228.122988)
		(width 0.18288)
		(layer "In2.Cu")
		(net "M_B_CPU0_SB_DQ<15>")
	)
	(segment
		(start 316.802008 -213.561422)
		(end 316.491112 -213.561422)
		(width 0.18288)
		(layer "In2.Cu")
		(net "M_B_CPU0_SB_DQ<15>")
	)
	(arc
		(start 335.41335 -230.402384)
		(mid 335.136875 -230.335064)
		(end 334.862678 -230.41102)
		(width 0.088646)
		(layer "In2.Cu")
		(net "M_B_CPU0_SB_DQ<15>")
	)
	(arc
		(start 335.802478 -230.41102)
		(mid 335.61528 -230.461163)
		(end 335.428082 -230.41102)
		(width 0.088646)
		(layer "In2.Cu")
		(net "M_B_CPU0_SB_DQ<15>")
	)
	(arc
		(start 336.641694 -230.484426)
		(mid 336.499949 -230.465764)
		(end 336.367882 -230.41102)
		(width 0.088646)
		(layer "In2.Cu")
		(net "M_B_CPU0_SB_DQ<15>")
	)
	(arc
		(start 336.367882 -230.41102)
		(mid 336.085324 -230.335371)
		(end 335.802732 -230.41102)
		(width 0.088646)
		(layer "In2.Cu")
		(net "M_B_CPU0_SB_DQ<15>")
	)
	(arc
		(start 333.548482 -230.41102)
		(mid 333.526868 -230.39663)
		(end 333.507334 -230.379524)
		(width 0.088646)
		(layer "In2.Cu")
		(net "M_B_CPU0_SB_DQ<15>")
	)
	(arc
		(start 333.922878 -230.41102)
		(mid 333.73568 -230.461163)
		(end 333.548482 -230.41102)
		(width 0.088646)
		(layer "In2.Cu")
		(net "M_B_CPU0_SB_DQ<15>")
	)
	(arc
		(start 334.862678 -230.41102)
		(mid 334.67548 -230.461163)
		(end 334.488282 -230.41102)
		(width 0.088646)
		(layer "In2.Cu")
		(net "M_B_CPU0_SB_DQ<15>")
	)
	(arc
		(start 337.965034 -230.900478)
		(mid 337.50425 -230.592592)
		(end 336.960718 -230.484426)
		(width 0.088646)
		(layer "In2.Cu")
		(net "M_B_CPU0_SB_DQ<15>")
	)
	(arc
		(start 334.47355 -230.402384)
		(mid 334.197075 -230.335064)
		(end 333.922878 -230.41102)
		(width 0.088646)
		(layer "In2.Cu")
		(net "M_B_CPU0_SB_DQ<15>")
	)
	(segment
		(start 292.940486 -215.591644)
		(end 292.68547 -215.591644)
		(width 0.101854)
		(layer "F.Cu")
		(net "M_B_CPU0_SB_DQ<14>")
	)
	(segment
		(start 292.67531 -215.581484)
		(end 291.937948 -215.581484)
		(width 0.20066)
		(layer "F.Cu")
		(net "M_B_CPU0_SB_DQ<14>")
	)
	(segment
		(start 296.584878 -216.016586)
		(end 296.373042 -216.228422)
		(width 0.20066)
		(layer "F.Cu")
		(net "M_B_CPU0_SB_DQ<14>")
	)
	(segment
		(start 338.434934 -232.250488)
		(end 338.43468 -232.250234)
		(width 0.20066)
		(layer "F.Cu")
		(net "M_B_CPU0_SB_DQ<14>")
	)
	(segment
		(start 295.777158 -216.061036)
		(end 295.777158 -215.735408)
		(width 0.20066)
		(layer "F.Cu")
		(net "M_B_CPU0_SB_DQ<14>")
	)
	(segment
		(start 296.373042 -216.228422)
		(end 295.944544 -216.228422)
		(width 0.20066)
		(layer "F.Cu")
		(net "M_B_CPU0_SB_DQ<14>")
	)
	(segment
		(start 295.633394 -215.591644)
		(end 295.000426 -215.591644)
		(width 0.20066)
		(layer "F.Cu")
		(net "M_B_CPU0_SB_DQ<14>")
	)
	(segment
		(start 292.68547 -215.591644)
		(end 292.67531 -215.581484)
		(width 0.101854)
		(layer "F.Cu")
		(net "M_B_CPU0_SB_DQ<14>")
	)
	(segment
		(start 338.43468 -232.250234)
		(end 338.43468 -231.714548)
		(width 0.20066)
		(layer "F.Cu")
		(net "M_B_CPU0_SB_DQ<14>")
	)
	(segment
		(start 297.899582 -216.016586)
		(end 296.584878 -216.016586)
		(width 0.20066)
		(layer "F.Cu")
		(net "M_B_CPU0_SB_DQ<14>")
	)
	(segment
		(start 291.937948 -215.581484)
		(end 291.502846 -216.016586)
		(width 0.20066)
		(layer "F.Cu")
		(net "M_B_CPU0_SB_DQ<14>")
	)
	(segment
		(start 295.000426 -215.591644)
		(end 292.940486 -215.591644)
		(width 0.1016)
		(layer "F.Cu")
		(net "M_B_CPU0_SB_DQ<14>")
	)
	(segment
		(start 295.944544 -216.228422)
		(end 295.777158 -216.061036)
		(width 0.20066)
		(layer "F.Cu")
		(net "M_B_CPU0_SB_DQ<14>")
	)
	(segment
		(start 299.004482 -216.016586)
		(end 297.899582 -216.016586)
		(width 0.20066)
		(layer "F.Cu")
		(net "M_B_CPU0_SB_DQ<14>")
	)
	(segment
		(start 295.777158 -215.735408)
		(end 295.633394 -215.591644)
		(width 0.20066)
		(layer "F.Cu")
		(net "M_B_CPU0_SB_DQ<14>")
	)
	(segment
		(start 291.502846 -216.016586)
		(end 290.355782 -216.016586)
		(width 0.20066)
		(layer "F.Cu")
		(net "M_B_CPU0_SB_DQ<14>")
	)
	(segment
		(start 317.293498 -216.397586)
		(end 317.100458 -216.204546)
		(width 0.18288)
		(layer "In2.Cu")
		(net "M_B_CPU0_SB_DQ<14>")
	)
	(segment
		(start 317.100458 -216.204546)
		(end 317.100458 -215.450928)
		(width 0.18288)
		(layer "In2.Cu")
		(net "M_B_CPU0_SB_DQ<14>")
	)
	(segment
		(start 337.876642 -231.283002)
		(end 337.770216 -231.220772)
		(width 0.088646)
		(layer "In2.Cu")
		(net "M_B_CPU0_SB_DQ<14>")
	)
	(segment
		(start 302.000158 -216.22258)
		(end 300.702726 -216.22258)
		(width 0.18288)
		(layer "In2.Cu")
		(net "M_B_CPU0_SB_DQ<14>")
	)
	(segment
		(start 303.196498 -215.803226)
		(end 303.003458 -215.996266)
		(width 0.18288)
		(layer "In2.Cu")
		(net "M_B_CPU0_SB_DQ<14>")
	)
	(segment
		(start 315.295534 -216.204546)
		(end 315.295534 -215.450928)
		(width 0.18288)
		(layer "In2.Cu")
		(net "M_B_CPU0_SB_DQ<14>")
	)
	(segment
		(start 300.43628 -216.489026)
		(end 299.476922 -216.489026)
		(width 0.18288)
		(layer "In2.Cu")
		(net "M_B_CPU0_SB_DQ<14>")
	)
	(segment
		(start 311.455562 -215.599772)
		(end 310.289956 -216.765378)
		(width 0.18288)
		(layer "In2.Cu")
		(net "M_B_CPU0_SB_DQ<14>")
	)
	(segment
		(start 303.516538 -215.803226)
		(end 303.196498 -215.803226)
		(width 0.18288)
		(layer "In2.Cu")
		(net "M_B_CPU0_SB_DQ<14>")
	)
	(segment
		(start 317.774574 -216.277698)
		(end 317.654686 -216.397586)
		(width 0.18288)
		(layer "In2.Cu")
		(net "M_B_CPU0_SB_DQ<14>")
	)
	(segment
		(start 307.670454 -216.76995)
		(end 307.349906 -216.76995)
		(width 0.18288)
		(layer "In2.Cu")
		(net "M_B_CPU0_SB_DQ<14>")
	)
	(segment
		(start 310.016652 -216.765378)
		(end 309.61584 -216.364566)
		(width 0.18288)
		(layer "In2.Cu")
		(net "M_B_CPU0_SB_DQ<14>")
	)
	(segment
		(start 314.364116 -215.599772)
		(end 311.455562 -215.599772)
		(width 0.18288)
		(layer "In2.Cu")
		(net "M_B_CPU0_SB_DQ<14>")
	)
	(segment
		(start 315.102494 -215.257888)
		(end 314.706 -215.257888)
		(width 0.18288)
		(layer "In2.Cu")
		(net "M_B_CPU0_SB_DQ<14>")
	)
	(segment
		(start 305.911504 -216.767918)
		(end 304.879248 -216.767918)
		(width 0.18288)
		(layer "In2.Cu")
		(net "M_B_CPU0_SB_DQ<14>")
	)
	(segment
		(start 303.709578 -216.219532)
		(end 303.709578 -215.996266)
		(width 0.18288)
		(layer "In2.Cu")
		(net "M_B_CPU0_SB_DQ<14>")
	)
	(segment
		(start 332.761082 -230.925878)
		(end 332.51013 -230.925878)
		(width 0.088646)
		(layer "In2.Cu")
		(net "M_B_CPU0_SB_DQ<14>")
	)
	(segment
		(start 316.907418 -215.257888)
		(end 316.356492 -215.257888)
		(width 0.18288)
		(layer "In2.Cu")
		(net "M_B_CPU0_SB_DQ<14>")
	)
	(segment
		(start 316.163452 -215.450928)
		(end 316.163452 -216.204546)
		(width 0.18288)
		(layer "In2.Cu")
		(net "M_B_CPU0_SB_DQ<14>")
	)
	(segment
		(start 306.430934 -216.248488)
		(end 305.911504 -216.767918)
		(width 0.18288)
		(layer "In2.Cu")
		(net "M_B_CPU0_SB_DQ<14>")
	)
	(segment
		(start 336.837782 -231.22509)
		(end 336.83321 -231.222296)
		(width 0.088646)
		(layer "In2.Cu")
		(net "M_B_CPU0_SB_DQ<14>")
	)
	(segment
		(start 315.295534 -215.450928)
		(end 315.102494 -215.257888)
		(width 0.18288)
		(layer "In2.Cu")
		(net "M_B_CPU0_SB_DQ<14>")
	)
	(segment
		(start 303.709578 -215.996266)
		(end 303.516538 -215.803226)
		(width 0.18288)
		(layer "In2.Cu")
		(net "M_B_CPU0_SB_DQ<14>")
	)
	(segment
		(start 303.003458 -215.996266)
		(end 303.003458 -216.526872)
		(width 0.18288)
		(layer "In2.Cu")
		(net "M_B_CPU0_SB_DQ<14>")
	)
	(segment
		(start 299.476922 -216.489026)
		(end 299.004482 -216.016586)
		(width 0.18288)
		(layer "In2.Cu")
		(net "M_B_CPU0_SB_DQ<14>")
	)
	(segment
		(start 315.970412 -216.397586)
		(end 315.488574 -216.397586)
		(width 0.18288)
		(layer "In2.Cu")
		(net "M_B_CPU0_SB_DQ<14>")
	)
	(segment
		(start 300.702726 -216.22258)
		(end 300.43628 -216.489026)
		(width 0.18288)
		(layer "In2.Cu")
		(net "M_B_CPU0_SB_DQ<14>")
	)
	(segment
		(start 304.879248 -216.767918)
		(end 304.523902 -216.412572)
		(width 0.18288)
		(layer "In2.Cu")
		(net "M_B_CPU0_SB_DQ<14>")
	)
	(segment
		(start 335.897982 -231.22509)
		(end 335.898236 -231.224836)
		(width 0.088646)
		(layer "In2.Cu")
		(net "M_B_CPU0_SB_DQ<14>")
	)
	(segment
		(start 338.43468 -231.714548)
		(end 338.434426 -231.714294)
		(width 0.088646)
		(layer "In2.Cu")
		(net "M_B_CPU0_SB_DQ<14>")
	)
	(segment
		(start 315.488574 -216.397586)
		(end 315.295534 -216.204546)
		(width 0.18288)
		(layer "In2.Cu")
		(net "M_B_CPU0_SB_DQ<14>")
	)
	(segment
		(start 304.523902 -216.412572)
		(end 303.902618 -216.412572)
		(width 0.18288)
		(layer "In2.Cu")
		(net "M_B_CPU0_SB_DQ<14>")
	)
	(segment
		(start 316.356492 -215.257888)
		(end 316.163452 -215.450928)
		(width 0.18288)
		(layer "In2.Cu")
		(net "M_B_CPU0_SB_DQ<14>")
	)
	(segment
		(start 302.49749 -216.719912)
		(end 302.000158 -216.22258)
		(width 0.18288)
		(layer "In2.Cu")
		(net "M_B_CPU0_SB_DQ<14>")
	)
	(segment
		(start 332.264258 -230.680006)
		(end 327.516998 -225.932746)
		(width 0.18288)
		(layer "In2.Cu")
		(net "M_B_CPU0_SB_DQ<14>")
	)
	(segment
		(start 317.654686 -216.397586)
		(end 317.293498 -216.397586)
		(width 0.18288)
		(layer "In2.Cu")
		(net "M_B_CPU0_SB_DQ<14>")
	)
	(segment
		(start 327.516998 -225.932746)
		(end 327.516998 -225.746818)
		(width 0.18288)
		(layer "In2.Cu")
		(net "M_B_CPU0_SB_DQ<14>")
	)
	(segment
		(start 333.000858 -231.165654)
		(end 332.761082 -230.925878)
		(width 0.088646)
		(layer "In2.Cu")
		(net "M_B_CPU0_SB_DQ<14>")
	)
	(segment
		(start 317.100458 -215.450928)
		(end 316.907418 -215.257888)
		(width 0.18288)
		(layer "In2.Cu")
		(net "M_B_CPU0_SB_DQ<14>")
	)
	(segment
		(start 306.828444 -216.248488)
		(end 306.430934 -216.248488)
		(width 0.18288)
		(layer "In2.Cu")
		(net "M_B_CPU0_SB_DQ<14>")
	)
	(segment
		(start 332.51013 -230.925878)
		(end 332.264258 -230.680006)
		(width 0.088646)
		(layer "In2.Cu")
		(net "M_B_CPU0_SB_DQ<14>")
	)
	(segment
		(start 308.075838 -216.364566)
		(end 307.670454 -216.76995)
		(width 0.18288)
		(layer "In2.Cu")
		(net "M_B_CPU0_SB_DQ<14>")
	)
	(segment
		(start 302.810418 -216.719912)
		(end 302.49749 -216.719912)
		(width 0.18288)
		(layer "In2.Cu")
		(net "M_B_CPU0_SB_DQ<14>")
	)
	(segment
		(start 303.003458 -216.526872)
		(end 302.810418 -216.719912)
		(width 0.18288)
		(layer "In2.Cu")
		(net "M_B_CPU0_SB_DQ<14>")
	)
	(segment
		(start 310.289956 -216.765378)
		(end 310.016652 -216.765378)
		(width 0.18288)
		(layer "In2.Cu")
		(net "M_B_CPU0_SB_DQ<14>")
	)
	(segment
		(start 309.61584 -216.364566)
		(end 308.075838 -216.364566)
		(width 0.18288)
		(layer "In2.Cu")
		(net "M_B_CPU0_SB_DQ<14>")
	)
	(segment
		(start 316.163452 -216.204546)
		(end 315.970412 -216.397586)
		(width 0.18288)
		(layer "In2.Cu")
		(net "M_B_CPU0_SB_DQ<14>")
	)
	(segment
		(start 314.706 -215.257888)
		(end 314.364116 -215.599772)
		(width 0.18288)
		(layer "In2.Cu")
		(net "M_B_CPU0_SB_DQ<14>")
	)
	(segment
		(start 336.842354 -231.22763)
		(end 336.837782 -231.22509)
		(width 0.088646)
		(layer "In2.Cu")
		(net "M_B_CPU0_SB_DQ<14>")
	)
	(segment
		(start 307.349906 -216.76995)
		(end 306.828444 -216.248488)
		(width 0.18288)
		(layer "In2.Cu")
		(net "M_B_CPU0_SB_DQ<14>")
	)
	(segment
		(start 318.047878 -216.277698)
		(end 317.774574 -216.277698)
		(width 0.18288)
		(layer "In2.Cu")
		(net "M_B_CPU0_SB_DQ<14>")
	)
	(segment
		(start 327.516998 -225.746818)
		(end 318.047878 -216.277698)
		(width 0.18288)
		(layer "In2.Cu")
		(net "M_B_CPU0_SB_DQ<14>")
	)
	(segment
		(start 303.902618 -216.412572)
		(end 303.709578 -216.219532)
		(width 0.18288)
		(layer "In2.Cu")
		(net "M_B_CPU0_SB_DQ<14>")
	)
	(arc
		(start 336.83321 -231.222296)
		(mid 336.552546 -231.149288)
		(end 336.272632 -231.22509)
		(width 0.088646)
		(layer "In2.Cu")
		(net "M_B_CPU0_SB_DQ<14>")
	)
	(arc
		(start 335.332832 -231.224836)
		(mid 335.145634 -231.274979)
		(end 334.958436 -231.224836)
		(width 0.088646)
		(layer "In2.Cu")
		(net "M_B_CPU0_SB_DQ<14>")
	)
	(arc
		(start 337.212432 -231.22509)
		(mid 337.027738 -231.275191)
		(end 336.842354 -231.22763)
		(width 0.088646)
		(layer "In2.Cu")
		(net "M_B_CPU0_SB_DQ<14>")
	)
	(arc
		(start 334.393032 -231.224836)
		(mid 334.205834 -231.274979)
		(end 334.018636 -231.224836)
		(width 0.088646)
		(layer "In2.Cu")
		(net "M_B_CPU0_SB_DQ<14>")
	)
	(arc
		(start 334.018636 -231.224836)
		(mid 333.735934 -231.149094)
		(end 333.453232 -231.224836)
		(width 0.088646)
		(layer "In2.Cu")
		(net "M_B_CPU0_SB_DQ<14>")
	)
	(arc
		(start 334.958436 -231.224836)
		(mid 334.675734 -231.149094)
		(end 334.393032 -231.224836)
		(width 0.088646)
		(layer "In2.Cu")
		(net "M_B_CPU0_SB_DQ<14>")
	)
	(arc
		(start 336.272632 -231.22509)
		(mid 336.085324 -231.275199)
		(end 335.897982 -231.22509)
		(width 0.088646)
		(layer "In2.Cu")
		(net "M_B_CPU0_SB_DQ<14>")
	)
	(arc
		(start 337.770216 -231.220772)
		(mid 337.490755 -231.149335)
		(end 337.212432 -231.22509)
		(width 0.088646)
		(layer "In2.Cu")
		(net "M_B_CPU0_SB_DQ<14>")
	)
	(arc
		(start 338.434426 -231.714294)
		(mid 338.169302 -231.480843)
		(end 337.876642 -231.283002)
		(width 0.088646)
		(layer "In2.Cu")
		(net "M_B_CPU0_SB_DQ<14>")
	)
	(arc
		(start 335.898236 -231.224836)
		(mid 335.615534 -231.149094)
		(end 335.332832 -231.224836)
		(width 0.088646)
		(layer "In2.Cu")
		(net "M_B_CPU0_SB_DQ<14>")
	)
	(arc
		(start 333.078836 -231.224836)
		(mid 333.037906 -231.197803)
		(end 333.000858 -231.165654)
		(width 0.088646)
		(layer "In2.Cu")
		(net "M_B_CPU0_SB_DQ<14>")
	)
	(arc
		(start 333.453232 -231.224836)
		(mid 333.266034 -231.274979)
		(end 333.078836 -231.224836)
		(width 0.088646)
		(layer "In2.Cu")
		(net "M_B_CPU0_SB_DQ<14>")
	)
	(segment
		(start 294.904414 -215.166702)
		(end 293.799514 -215.166702)
		(width 0.20066)
		(layer "F.Cu")
		(net "M_B_CPU0_SB_DQ<13>")
	)
	(segment
		(start 288.305748 -215.37803)
		(end 287.801304 -215.37803)
		(width 0.20066)
		(layer "F.Cu")
		(net "M_B_CPU0_SB_DQ<13>")
	)
	(segment
		(start 287.801304 -215.37803)
		(end 287.589976 -215.166702)
		(width 0.20066)
		(layer "F.Cu")
		(net "M_B_CPU0_SB_DQ<13>")
	)
	(segment
		(start 337.025234 -231.436164)
		(end 337.025234 -230.900478)
		(width 0.20066)
		(layer "F.Cu")
		(net "M_B_CPU0_SB_DQ<13>")
	)
	(segment
		(start 287.589976 -215.166702)
		(end 286.255714 -215.166702)
		(width 0.20066)
		(layer "F.Cu")
		(net "M_B_CPU0_SB_DQ<13>")
	)
	(segment
		(start 291.735256 -214.74176)
		(end 291.556694 -214.74176)
		(width 0.20066)
		(layer "F.Cu")
		(net "M_B_CPU0_SB_DQ<13>")
	)
	(segment
		(start 289.231578 -214.73287)
		(end 288.62274 -214.73287)
		(width 0.20066)
		(layer "F.Cu")
		(net "M_B_CPU0_SB_DQ<13>")
	)
	(segment
		(start 288.62274 -214.73287)
		(end 288.46018 -214.89543)
		(width 0.20066)
		(layer "F.Cu")
		(net "M_B_CPU0_SB_DQ<13>")
	)
	(segment
		(start 291.556694 -214.74176)
		(end 291.225986 -214.74176)
		(width 0.101854)
		(layer "F.Cu")
		(net "M_B_CPU0_SB_DQ<13>")
	)
	(segment
		(start 293.799514 -215.166702)
		(end 292.160198 -215.166702)
		(width 0.20066)
		(layer "F.Cu")
		(net "M_B_CPU0_SB_DQ<13>")
	)
	(segment
		(start 289.240468 -214.74176)
		(end 289.231578 -214.73287)
		(width 0.1016)
		(layer "F.Cu")
		(net "M_B_CPU0_SB_DQ<13>")
	)
	(segment
		(start 288.46018 -215.223598)
		(end 288.305748 -215.37803)
		(width 0.20066)
		(layer "F.Cu")
		(net "M_B_CPU0_SB_DQ<13>")
	)
	(segment
		(start 291.225986 -214.74176)
		(end 289.240468 -214.74176)
		(width 0.1016)
		(layer "F.Cu")
		(net "M_B_CPU0_SB_DQ<13>")
	)
	(segment
		(start 288.46018 -214.89543)
		(end 288.46018 -215.223598)
		(width 0.20066)
		(layer "F.Cu")
		(net "M_B_CPU0_SB_DQ<13>")
	)
	(segment
		(start 337.02498 -231.436418)
		(end 337.025234 -231.436164)
		(width 0.20066)
		(layer "F.Cu")
		(net "M_B_CPU0_SB_DQ<13>")
	)
	(segment
		(start 292.160198 -215.166702)
		(end 291.735256 -214.74176)
		(width 0.20066)
		(layer "F.Cu")
		(net "M_B_CPU0_SB_DQ<13>")
	)
	(segment
		(start 309.588916 -215.729312)
		(end 308.181756 -215.729312)
		(width 0.18288)
		(layer "In2.Cu")
		(net "M_B_CPU0_SB_DQ<13>")
	)
	(segment
		(start 312.578242 -214.995506)
		(end 312.313574 -214.730838)
		(width 0.18288)
		(layer "In2.Cu")
		(net "M_B_CPU0_SB_DQ<13>")
	)
	(segment
		(start 295.508426 -215.31961)
		(end 295.355518 -215.166702)
		(width 0.18288)
		(layer "In2.Cu")
		(net "M_B_CPU0_SB_DQ<13>")
	)
	(segment
		(start 302.091598 -215.691974)
		(end 300.57217 -215.691974)
		(width 0.18288)
		(layer "In2.Cu")
		(net "M_B_CPU0_SB_DQ<13>")
	)
	(segment
		(start 313.017154 -214.995506)
		(end 312.578242 -214.995506)
		(width 0.18288)
		(layer "In2.Cu")
		(net "M_B_CPU0_SB_DQ<13>")
	)
	(segment
		(start 336.374994 -230.636826)
		(end 336.272632 -230.57612)
		(width 0.088646)
		(layer "In2.Cu")
		(net "M_B_CPU0_SB_DQ<13>")
	)
	(segment
		(start 311.339484 -214.730838)
		(end 310.784748 -215.285574)
		(width 0.18288)
		(layer "In2.Cu")
		(net "M_B_CPU0_SB_DQ<13>")
	)
	(segment
		(start 310.032654 -215.285574)
		(end 309.588916 -215.729312)
		(width 0.18288)
		(layer "In2.Cu")
		(net "M_B_CPU0_SB_DQ<13>")
	)
	(segment
		(start 328.02449 -225.721418)
		(end 328.02449 -225.535744)
		(width 0.18288)
		(layer "In2.Cu")
		(net "M_B_CPU0_SB_DQ<13>")
	)
	(segment
		(start 302.506126 -215.277446)
		(end 302.091598 -215.691974)
		(width 0.18288)
		(layer "In2.Cu")
		(net "M_B_CPU0_SB_DQ<13>")
	)
	(segment
		(start 299.442378 -215.423242)
		(end 299.273976 -215.591644)
		(width 0.18288)
		(layer "In2.Cu")
		(net "M_B_CPU0_SB_DQ<13>")
	)
	(segment
		(start 332.623922 -230.32085)
		(end 328.02449 -225.721418)
		(width 0.18288)
		(layer "In2.Cu")
		(net "M_B_CPU0_SB_DQ<13>")
	)
	(segment
		(start 308.181756 -215.729312)
		(end 307.73243 -215.279986)
		(width 0.18288)
		(layer "In2.Cu")
		(net "M_B_CPU0_SB_DQ<13>")
	)
	(segment
		(start 295.508426 -215.86825)
		(end 295.508426 -215.31961)
		(width 0.18288)
		(layer "In2.Cu")
		(net "M_B_CPU0_SB_DQ<13>")
	)
	(segment
		(start 313.281822 -214.730838)
		(end 313.017154 -214.995506)
		(width 0.18288)
		(layer "In2.Cu")
		(net "M_B_CPU0_SB_DQ<13>")
	)
	(segment
		(start 335.347564 -230.584756)
		(end 335.332832 -230.57612)
		(width 0.088646)
		(layer "In2.Cu")
		(net "M_B_CPU0_SB_DQ<13>")
	)
	(segment
		(start 298.744894 -215.591644)
		(end 298.201588 -215.048338)
		(width 0.18288)
		(layer "In2.Cu")
		(net "M_B_CPU0_SB_DQ<13>")
	)
	(segment
		(start 300.303438 -215.423242)
		(end 299.442378 -215.423242)
		(width 0.18288)
		(layer "In2.Cu")
		(net "M_B_CPU0_SB_DQ<13>")
	)
	(segment
		(start 295.355518 -215.166702)
		(end 294.904414 -215.166702)
		(width 0.18288)
		(layer "In2.Cu")
		(net "M_B_CPU0_SB_DQ<13>")
	)
	(segment
		(start 328.02449 -225.535744)
		(end 317.219584 -214.730838)
		(width 0.18288)
		(layer "In2.Cu")
		(net "M_B_CPU0_SB_DQ<13>")
	)
	(segment
		(start 333.336138 -230.486458)
		(end 332.78953 -230.486458)
		(width 0.088646)
		(layer "In2.Cu")
		(net "M_B_CPU0_SB_DQ<13>")
	)
	(segment
		(start 306.185316 -215.472264)
		(end 304.72634 -215.472264)
		(width 0.18288)
		(layer "In2.Cu")
		(net "M_B_CPU0_SB_DQ<13>")
	)
	(segment
		(start 299.273976 -215.591644)
		(end 298.744894 -215.591644)
		(width 0.18288)
		(layer "In2.Cu")
		(net "M_B_CPU0_SB_DQ<13>")
	)
	(segment
		(start 304.72634 -215.472264)
		(end 304.488088 -215.710516)
		(width 0.18288)
		(layer "In2.Cu")
		(net "M_B_CPU0_SB_DQ<13>")
	)
	(segment
		(start 297.537378 -215.048338)
		(end 296.524426 -216.06129)
		(width 0.18288)
		(layer "In2.Cu")
		(net "M_B_CPU0_SB_DQ<13>")
	)
	(segment
		(start 307.333904 -215.279986)
		(end 306.906168 -215.707722)
		(width 0.18288)
		(layer "In2.Cu")
		(net "M_B_CPU0_SB_DQ<13>")
	)
	(segment
		(start 306.420774 -215.707722)
		(end 306.185316 -215.472264)
		(width 0.18288)
		(layer "In2.Cu")
		(net "M_B_CPU0_SB_DQ<13>")
	)
	(segment
		(start 307.73243 -215.279986)
		(end 307.333904 -215.279986)
		(width 0.18288)
		(layer "In2.Cu")
		(net "M_B_CPU0_SB_DQ<13>")
	)
	(segment
		(start 333.467964 -230.584756)
		(end 333.453232 -230.57612)
		(width 0.088646)
		(layer "In2.Cu")
		(net "M_B_CPU0_SB_DQ<13>")
	)
	(segment
		(start 335.897982 -230.57612)
		(end 335.898236 -230.57612)
		(width 0.088646)
		(layer "In2.Cu")
		(net "M_B_CPU0_SB_DQ<13>")
	)
	(segment
		(start 337.025234 -230.900478)
		(end 336.374994 -230.636826)
		(width 0.088646)
		(layer "In2.Cu")
		(net "M_B_CPU0_SB_DQ<13>")
	)
	(segment
		(start 310.784748 -215.285574)
		(end 310.032654 -215.285574)
		(width 0.18288)
		(layer "In2.Cu")
		(net "M_B_CPU0_SB_DQ<13>")
	)
	(segment
		(start 332.78953 -230.486458)
		(end 332.623922 -230.32085)
		(width 0.088646)
		(layer "In2.Cu")
		(net "M_B_CPU0_SB_DQ<13>")
	)
	(segment
		(start 295.701466 -216.06129)
		(end 295.508426 -215.86825)
		(width 0.18288)
		(layer "In2.Cu")
		(net "M_B_CPU0_SB_DQ<13>")
	)
	(segment
		(start 317.219584 -214.730838)
		(end 313.281822 -214.730838)
		(width 0.18288)
		(layer "In2.Cu")
		(net "M_B_CPU0_SB_DQ<13>")
	)
	(segment
		(start 312.313574 -214.730838)
		(end 311.339484 -214.730838)
		(width 0.18288)
		(layer "In2.Cu")
		(net "M_B_CPU0_SB_DQ<13>")
	)
	(segment
		(start 298.201588 -215.048338)
		(end 297.537378 -215.048338)
		(width 0.18288)
		(layer "In2.Cu")
		(net "M_B_CPU0_SB_DQ<13>")
	)
	(segment
		(start 306.906168 -215.707722)
		(end 306.420774 -215.707722)
		(width 0.18288)
		(layer "In2.Cu")
		(net "M_B_CPU0_SB_DQ<13>")
	)
	(segment
		(start 334.407764 -230.584756)
		(end 334.393032 -230.57612)
		(width 0.088646)
		(layer "In2.Cu")
		(net "M_B_CPU0_SB_DQ<13>")
	)
	(segment
		(start 303.781968 -215.277446)
		(end 302.506126 -215.277446)
		(width 0.18288)
		(layer "In2.Cu")
		(net "M_B_CPU0_SB_DQ<13>")
	)
	(segment
		(start 296.524426 -216.06129)
		(end 295.701466 -216.06129)
		(width 0.18288)
		(layer "In2.Cu")
		(net "M_B_CPU0_SB_DQ<13>")
	)
	(segment
		(start 300.57217 -215.691974)
		(end 300.303438 -215.423242)
		(width 0.18288)
		(layer "In2.Cu")
		(net "M_B_CPU0_SB_DQ<13>")
	)
	(segment
		(start 304.488088 -215.710516)
		(end 304.215038 -215.710516)
		(width 0.18288)
		(layer "In2.Cu")
		(net "M_B_CPU0_SB_DQ<13>")
	)
	(segment
		(start 304.215038 -215.710516)
		(end 303.781968 -215.277446)
		(width 0.18288)
		(layer "In2.Cu")
		(net "M_B_CPU0_SB_DQ<13>")
	)
	(arc
		(start 335.332832 -230.57612)
		(mid 335.145634 -230.525977)
		(end 334.958436 -230.57612)
		(width 0.088646)
		(layer "In2.Cu")
		(net "M_B_CPU0_SB_DQ<13>")
	)
	(arc
		(start 336.272632 -230.57612)
		(mid 336.085324 -230.525977)
		(end 335.897982 -230.57612)
		(width 0.088646)
		(layer "In2.Cu")
		(net "M_B_CPU0_SB_DQ<13>")
	)
	(arc
		(start 333.453232 -230.57612)
		(mid 333.406156 -230.54586)
		(end 333.3623 -230.511096)
		(width 0.088646)
		(layer "In2.Cu")
		(net "M_B_CPU0_SB_DQ<13>")
	)
	(arc
		(start 334.018636 -230.57612)
		(mid 333.744437 -230.651955)
		(end 333.467964 -230.584756)
		(width 0.088646)
		(layer "In2.Cu")
		(net "M_B_CPU0_SB_DQ<13>")
	)
	(arc
		(start 334.958436 -230.57612)
		(mid 334.684237 -230.651955)
		(end 334.407764 -230.584756)
		(width 0.088646)
		(layer "In2.Cu")
		(net "M_B_CPU0_SB_DQ<13>")
	)
	(arc
		(start 333.3623 -230.511096)
		(mid 333.349024 -230.498984)
		(end 333.336138 -230.486458)
		(width 0.088646)
		(layer "In2.Cu")
		(net "M_B_CPU0_SB_DQ<13>")
	)
	(arc
		(start 335.898236 -230.57612)
		(mid 335.624037 -230.651955)
		(end 335.347564 -230.584756)
		(width 0.088646)
		(layer "In2.Cu")
		(net "M_B_CPU0_SB_DQ<13>")
	)
	(arc
		(start 334.393032 -230.57612)
		(mid 334.205834 -230.525977)
		(end 334.018636 -230.57612)
		(width 0.088646)
		(layer "In2.Cu")
		(net "M_B_CPU0_SB_DQ<13>")
	)
	(segment
		(start 292.005512 -216.441782)
		(end 291.556694 -216.441782)
		(width 0.20066)
		(layer "F.Cu")
		(net "M_B_CPU0_SB_DQ<12>")
	)
	(segment
		(start 294.904414 -216.866724)
		(end 293.799514 -216.866724)
		(width 0.20066)
		(layer "F.Cu")
		(net "M_B_CPU0_SB_DQ<12>")
	)
	(segment
		(start 289.48761 -216.441782)
		(end 289.239706 -216.441782)
		(width 0.101854)
		(layer "F.Cu")
		(net "M_B_CPU0_SB_DQ<12>")
	)
	(segment
		(start 293.799514 -216.866724)
		(end 292.430454 -216.866724)
		(width 0.20066)
		(layer "F.Cu")
		(net "M_B_CPU0_SB_DQ<12>")
	)
	(segment
		(start 287.589976 -216.866724)
		(end 286.255714 -216.866724)
		(width 0.20066)
		(layer "F.Cu")
		(net "M_B_CPU0_SB_DQ<12>")
	)
	(segment
		(start 288.46018 -216.932764)
		(end 288.28746 -217.105484)
		(width 0.20066)
		(layer "F.Cu")
		(net "M_B_CPU0_SB_DQ<12>")
	)
	(segment
		(start 288.46018 -216.643204)
		(end 288.46018 -216.932764)
		(width 0.20066)
		(layer "F.Cu")
		(net "M_B_CPU0_SB_DQ<12>")
	)
	(segment
		(start 336.55508 -232.250234)
		(end 336.55508 -231.714548)
		(width 0.20066)
		(layer "F.Cu")
		(net "M_B_CPU0_SB_DQ<12>")
	)
	(segment
		(start 287.828736 -217.105484)
		(end 287.589976 -216.866724)
		(width 0.20066)
		(layer "F.Cu")
		(net "M_B_CPU0_SB_DQ<12>")
	)
	(segment
		(start 288.28746 -217.105484)
		(end 287.828736 -217.105484)
		(width 0.20066)
		(layer "F.Cu")
		(net "M_B_CPU0_SB_DQ<12>")
	)
	(segment
		(start 289.239706 -216.441782)
		(end 289.231578 -216.433654)
		(width 0.101854)
		(layer "F.Cu")
		(net "M_B_CPU0_SB_DQ<12>")
	)
	(segment
		(start 336.555334 -232.250488)
		(end 336.55508 -232.250234)
		(width 0.20066)
		(layer "F.Cu")
		(net "M_B_CPU0_SB_DQ<12>")
	)
	(segment
		(start 292.430454 -216.866724)
		(end 292.005512 -216.441782)
		(width 0.20066)
		(layer "F.Cu")
		(net "M_B_CPU0_SB_DQ<12>")
	)
	(segment
		(start 288.66973 -216.433654)
		(end 288.46018 -216.643204)
		(width 0.20066)
		(layer "F.Cu")
		(net "M_B_CPU0_SB_DQ<12>")
	)
	(segment
		(start 289.231578 -216.433654)
		(end 288.66973 -216.433654)
		(width 0.20066)
		(layer "F.Cu")
		(net "M_B_CPU0_SB_DQ<12>")
	)
	(segment
		(start 291.556694 -216.441782)
		(end 289.48761 -216.441782)
		(width 0.1016)
		(layer "F.Cu")
		(net "M_B_CPU0_SB_DQ<12>")
	)
	(segment
		(start 332.81747 -231.251506)
		(end 332.116938 -231.251506)
		(width 0.088646)
		(layer "In2.Cu")
		(net "M_B_CPU0_SB_DQ<12>")
	)
	(segment
		(start 331.904848 -231.039416)
		(end 326.980804 -226.115372)
		(width 0.18288)
		(layer "In2.Cu")
		(net "M_B_CPU0_SB_DQ<12>")
	)
	(segment
		(start 316.234826 -216.914984)
		(end 314.993782 -216.914984)
		(width 0.18288)
		(layer "In2.Cu")
		(net "M_B_CPU0_SB_DQ<12>")
	)
	(segment
		(start 295.714166 -218.005914)
		(end 295.472104 -217.763852)
		(width 0.18288)
		(layer "In2.Cu")
		(net "M_B_CPU0_SB_DQ<12>")
	)
	(segment
		(start 335.862422 -231.424734)
		(end 335.802732 -231.39019)
		(width 0.088646)
		(layer "In2.Cu")
		(net "M_B_CPU0_SB_DQ<12>")
	)
	(segment
		(start 314.068968 -216.210388)
		(end 313.854846 -216.42451)
		(width 0.18288)
		(layer "In2.Cu")
		(net "M_B_CPU0_SB_DQ<12>")
	)
	(segment
		(start 332.116938 -231.251506)
		(end 331.904848 -231.039416)
		(width 0.088646)
		(layer "In2.Cu")
		(net "M_B_CPU0_SB_DQ<12>")
	)
	(segment
		(start 298.498514 -217.13063)
		(end 298.498514 -216.780872)
		(width 0.18288)
		(layer "In2.Cu")
		(net "M_B_CPU0_SB_DQ<12>")
	)
	(segment
		(start 298.65955 -217.291666)
		(end 298.498514 -217.13063)
		(width 0.18288)
		(layer "In2.Cu")
		(net "M_B_CPU0_SB_DQ<12>")
	)
	(segment
		(start 296.67581 -217.313256)
		(end 296.48277 -217.506296)
		(width 0.18288)
		(layer "In2.Cu")
		(net "M_B_CPU0_SB_DQ<12>")
	)
	(segment
		(start 299.22216 -217.291666)
		(end 298.65955 -217.291666)
		(width 0.18288)
		(layer "In2.Cu")
		(net "M_B_CPU0_SB_DQ<12>")
	)
	(segment
		(start 317.966598 -216.914984)
		(end 317.070486 -216.914984)
		(width 0.18288)
		(layer "In2.Cu")
		(net "M_B_CPU0_SB_DQ<12>")
	)
	(segment
		(start 311.433464 -216.42451)
		(end 310.580024 -217.27795)
		(width 0.18288)
		(layer "In2.Cu")
		(net "M_B_CPU0_SB_DQ<12>")
	)
	(segment
		(start 295.279064 -216.866724)
		(end 294.904414 -216.866724)
		(width 0.18288)
		(layer "In2.Cu")
		(net "M_B_CPU0_SB_DQ<12>")
	)
	(segment
		(start 304.212752 -217.668602)
		(end 303.32172 -217.668602)
		(width 0.18288)
		(layer "In2.Cu")
		(net "M_B_CPU0_SB_DQ<12>")
	)
	(segment
		(start 306.588414 -217.561922)
		(end 306.315872 -217.28938)
		(width 0.18288)
		(layer "In2.Cu")
		(net "M_B_CPU0_SB_DQ<12>")
	)
	(segment
		(start 314.749434 -216.670636)
		(end 314.749434 -216.403682)
		(width 0.18288)
		(layer "In2.Cu")
		(net "M_B_CPU0_SB_DQ<12>")
	)
	(segment
		(start 298.338494 -216.620852)
		(end 297.45686 -216.620852)
		(width 0.18288)
		(layer "In2.Cu")
		(net "M_B_CPU0_SB_DQ<12>")
	)
	(segment
		(start 307.27777 -217.27795)
		(end 306.993798 -217.561922)
		(width 0.18288)
		(layer "In2.Cu")
		(net "M_B_CPU0_SB_DQ<12>")
	)
	(segment
		(start 300.241208 -217.044524)
		(end 299.469302 -217.044524)
		(width 0.18288)
		(layer "In2.Cu")
		(net "M_B_CPU0_SB_DQ<12>")
	)
	(segment
		(start 296.48277 -217.506296)
		(end 296.48277 -217.763852)
		(width 0.18288)
		(layer "In2.Cu")
		(net "M_B_CPU0_SB_DQ<12>")
	)
	(segment
		(start 303.32172 -217.668602)
		(end 302.918368 -217.26525)
		(width 0.18288)
		(layer "In2.Cu")
		(net "M_B_CPU0_SB_DQ<12>")
	)
	(segment
		(start 314.993782 -216.914984)
		(end 314.749434 -216.670636)
		(width 0.18288)
		(layer "In2.Cu")
		(net "M_B_CPU0_SB_DQ<12>")
	)
	(segment
		(start 295.472104 -217.763852)
		(end 295.472104 -217.059764)
		(width 0.18288)
		(layer "In2.Cu")
		(net "M_B_CPU0_SB_DQ<12>")
	)
	(segment
		(start 297.45686 -216.620852)
		(end 297.26382 -216.813892)
		(width 0.18288)
		(layer "In2.Cu")
		(net "M_B_CPU0_SB_DQ<12>")
	)
	(segment
		(start 302.918368 -217.26525)
		(end 300.461934 -217.26525)
		(width 0.18288)
		(layer "In2.Cu")
		(net "M_B_CPU0_SB_DQ<12>")
	)
	(segment
		(start 314.55614 -216.210388)
		(end 314.068968 -216.210388)
		(width 0.18288)
		(layer "In2.Cu")
		(net "M_B_CPU0_SB_DQ<12>")
	)
	(segment
		(start 297.26382 -216.813892)
		(end 297.26382 -217.061034)
		(width 0.18288)
		(layer "In2.Cu")
		(net "M_B_CPU0_SB_DQ<12>")
	)
	(segment
		(start 336.192876 -231.616758)
		(end 335.862422 -231.424734)
		(width 0.088646)
		(layer "In2.Cu")
		(net "M_B_CPU0_SB_DQ<12>")
	)
	(segment
		(start 316.789308 -216.633806)
		(end 316.516004 -216.633806)
		(width 0.18288)
		(layer "In2.Cu")
		(net "M_B_CPU0_SB_DQ<12>")
	)
	(segment
		(start 304.591974 -217.28938)
		(end 304.212752 -217.668602)
		(width 0.18288)
		(layer "In2.Cu")
		(net "M_B_CPU0_SB_DQ<12>")
	)
	(segment
		(start 310.580024 -217.27795)
		(end 307.27777 -217.27795)
		(width 0.18288)
		(layer "In2.Cu")
		(net "M_B_CPU0_SB_DQ<12>")
	)
	(segment
		(start 316.516004 -216.633806)
		(end 316.234826 -216.914984)
		(width 0.18288)
		(layer "In2.Cu")
		(net "M_B_CPU0_SB_DQ<12>")
	)
	(segment
		(start 296.48277 -217.763852)
		(end 296.240708 -218.005914)
		(width 0.18288)
		(layer "In2.Cu")
		(net "M_B_CPU0_SB_DQ<12>")
	)
	(segment
		(start 299.469302 -217.044524)
		(end 299.22216 -217.291666)
		(width 0.18288)
		(layer "In2.Cu")
		(net "M_B_CPU0_SB_DQ<12>")
	)
	(segment
		(start 326.980804 -225.92919)
		(end 317.966598 -216.914984)
		(width 0.18288)
		(layer "In2.Cu")
		(net "M_B_CPU0_SB_DQ<12>")
	)
	(segment
		(start 306.993798 -217.561922)
		(end 306.588414 -217.561922)
		(width 0.18288)
		(layer "In2.Cu")
		(net "M_B_CPU0_SB_DQ<12>")
	)
	(segment
		(start 317.070486 -216.914984)
		(end 316.789308 -216.633806)
		(width 0.18288)
		(layer "In2.Cu")
		(net "M_B_CPU0_SB_DQ<12>")
	)
	(segment
		(start 295.472104 -217.059764)
		(end 295.279064 -216.866724)
		(width 0.18288)
		(layer "In2.Cu")
		(net "M_B_CPU0_SB_DQ<12>")
	)
	(segment
		(start 296.240708 -218.005914)
		(end 295.714166 -218.005914)
		(width 0.18288)
		(layer "In2.Cu")
		(net "M_B_CPU0_SB_DQ<12>")
	)
	(segment
		(start 314.749434 -216.403682)
		(end 314.55614 -216.210388)
		(width 0.18288)
		(layer "In2.Cu")
		(net "M_B_CPU0_SB_DQ<12>")
	)
	(segment
		(start 332.866238 -231.300274)
		(end 332.81747 -231.251506)
		(width 0.088646)
		(layer "In2.Cu")
		(net "M_B_CPU0_SB_DQ<12>")
	)
	(segment
		(start 306.315872 -217.28938)
		(end 304.591974 -217.28938)
		(width 0.18288)
		(layer "In2.Cu")
		(net "M_B_CPU0_SB_DQ<12>")
	)
	(segment
		(start 300.461934 -217.26525)
		(end 300.241208 -217.044524)
		(width 0.18288)
		(layer "In2.Cu")
		(net "M_B_CPU0_SB_DQ<12>")
	)
	(segment
		(start 326.980804 -226.115372)
		(end 326.980804 -225.92919)
		(width 0.18288)
		(layer "In2.Cu")
		(net "M_B_CPU0_SB_DQ<12>")
	)
	(segment
		(start 298.498514 -216.780872)
		(end 298.338494 -216.620852)
		(width 0.18288)
		(layer "In2.Cu")
		(net "M_B_CPU0_SB_DQ<12>")
	)
	(segment
		(start 297.26382 -217.061034)
		(end 297.011598 -217.313256)
		(width 0.18288)
		(layer "In2.Cu")
		(net "M_B_CPU0_SB_DQ<12>")
	)
	(segment
		(start 313.854846 -216.42451)
		(end 311.433464 -216.42451)
		(width 0.18288)
		(layer "In2.Cu")
		(net "M_B_CPU0_SB_DQ<12>")
	)
	(segment
		(start 297.011598 -217.313256)
		(end 296.67581 -217.313256)
		(width 0.18288)
		(layer "In2.Cu")
		(net "M_B_CPU0_SB_DQ<12>")
	)
	(arc
		(start 335.428336 -231.39019)
		(mid 335.145634 -231.465932)
		(end 334.862932 -231.39019)
		(width 0.088646)
		(layer "In2.Cu")
		(net "M_B_CPU0_SB_DQ<12>")
	)
	(arc
		(start 332.983332 -231.39019)
		(mid 332.921837 -231.349071)
		(end 332.866238 -231.300274)
		(width 0.088646)
		(layer "In2.Cu")
		(net "M_B_CPU0_SB_DQ<12>")
	)
	(arc
		(start 334.862932 -231.39019)
		(mid 334.675734 -231.340047)
		(end 334.488536 -231.39019)
		(width 0.088646)
		(layer "In2.Cu")
		(net "M_B_CPU0_SB_DQ<12>")
	)
	(arc
		(start 333.923132 -231.39019)
		(mid 333.735934 -231.340047)
		(end 333.548736 -231.39019)
		(width 0.088646)
		(layer "In2.Cu")
		(net "M_B_CPU0_SB_DQ<12>")
	)
	(arc
		(start 334.488536 -231.39019)
		(mid 334.205834 -231.465932)
		(end 333.923132 -231.39019)
		(width 0.088646)
		(layer "In2.Cu")
		(net "M_B_CPU0_SB_DQ<12>")
	)
	(arc
		(start 335.802732 -231.39019)
		(mid 335.615534 -231.340047)
		(end 335.428336 -231.39019)
		(width 0.088646)
		(layer "In2.Cu")
		(net "M_B_CPU0_SB_DQ<12>")
	)
	(arc
		(start 333.548736 -231.39019)
		(mid 333.266034 -231.465932)
		(end 332.983332 -231.39019)
		(width 0.088646)
		(layer "In2.Cu")
		(net "M_B_CPU0_SB_DQ<12>")
	)
	(arc
		(start 336.55508 -231.714548)
		(mid 336.367498 -231.689645)
		(end 336.192876 -231.616758)
		(width 0.088646)
		(layer "In2.Cu")
		(net "M_B_CPU0_SB_DQ<12>")
	)
	(segment
		(start 295.693846 -220.390974)
		(end 295.693846 -220.542612)
		(width 0.20066)
		(layer "F.Cu")
		(net "M_B_CPU0_SB_DQ<11>")
	)
	(segment
		(start 338.434934 -233.87812)
		(end 338.43468 -233.877866)
		(width 0.20066)
		(layer "F.Cu")
		(net "M_B_CPU0_SB_DQ<11>")
	)
	(segment
		(start 299.004482 -220.266768)
		(end 297.899582 -220.266768)
		(width 0.20066)
		(layer "F.Cu")
		(net "M_B_CPU0_SB_DQ<11>")
	)
	(segment
		(start 295.000426 -220.69171)
		(end 292.927532 -220.69171)
		(width 0.1016)
		(layer "F.Cu")
		(net "M_B_CPU0_SB_DQ<11>")
	)
	(segment
		(start 295.82237 -220.26245)
		(end 295.693846 -220.390974)
		(width 0.20066)
		(layer "F.Cu")
		(net "M_B_CPU0_SB_DQ<11>")
	)
	(segment
		(start 292.927532 -220.69171)
		(end 292.689534 -220.69171)
		(width 0.101854)
		(layer "F.Cu")
		(net "M_B_CPU0_SB_DQ<11>")
	)
	(segment
		(start 292.178994 -220.392752)
		(end 292.05301 -220.266768)
		(width 0.20066)
		(layer "F.Cu")
		(net "M_B_CPU0_SB_DQ<11>")
	)
	(segment
		(start 292.321488 -220.705934)
		(end 292.178994 -220.56344)
		(width 0.20066)
		(layer "F.Cu")
		(net "M_B_CPU0_SB_DQ<11>")
	)
	(segment
		(start 295.544748 -220.69171)
		(end 295.000426 -220.69171)
		(width 0.20066)
		(layer "F.Cu")
		(net "M_B_CPU0_SB_DQ<11>")
	)
	(segment
		(start 297.08348 -220.266768)
		(end 296.875962 -220.474286)
		(width 0.20066)
		(layer "F.Cu")
		(net "M_B_CPU0_SB_DQ<11>")
	)
	(segment
		(start 295.693846 -220.542612)
		(end 295.544748 -220.69171)
		(width 0.20066)
		(layer "F.Cu")
		(net "M_B_CPU0_SB_DQ<11>")
	)
	(segment
		(start 296.217594 -220.26245)
		(end 295.82237 -220.26245)
		(width 0.20066)
		(layer "F.Cu")
		(net "M_B_CPU0_SB_DQ<11>")
	)
	(segment
		(start 297.899582 -220.266768)
		(end 297.08348 -220.266768)
		(width 0.20066)
		(layer "F.Cu")
		(net "M_B_CPU0_SB_DQ<11>")
	)
	(segment
		(start 292.67531 -220.705934)
		(end 292.321488 -220.705934)
		(width 0.20066)
		(layer "F.Cu")
		(net "M_B_CPU0_SB_DQ<11>")
	)
	(segment
		(start 338.43468 -233.877866)
		(end 338.43468 -233.34218)
		(width 0.20066)
		(layer "F.Cu")
		(net "M_B_CPU0_SB_DQ<11>")
	)
	(segment
		(start 296.875962 -220.474286)
		(end 296.42943 -220.474286)
		(width 0.20066)
		(layer "F.Cu")
		(net "M_B_CPU0_SB_DQ<11>")
	)
	(segment
		(start 292.178994 -220.56344)
		(end 292.178994 -220.392752)
		(width 0.20066)
		(layer "F.Cu")
		(net "M_B_CPU0_SB_DQ<11>")
	)
	(segment
		(start 292.689534 -220.69171)
		(end 292.67531 -220.705934)
		(width 0.101854)
		(layer "F.Cu")
		(net "M_B_CPU0_SB_DQ<11>")
	)
	(segment
		(start 296.42943 -220.474286)
		(end 296.217594 -220.26245)
		(width 0.20066)
		(layer "F.Cu")
		(net "M_B_CPU0_SB_DQ<11>")
	)
	(segment
		(start 292.05301 -220.266768)
		(end 290.355782 -220.266768)
		(width 0.20066)
		(layer "F.Cu")
		(net "M_B_CPU0_SB_DQ<11>")
	)
	(segment
		(start 302.372268 -220.853762)
		(end 302.223424 -220.704918)
		(width 0.18288)
		(layer "In2.Cu")
		(net "M_B_CPU0_SB_DQ<11>")
	)
	(segment
		(start 330.820522 -233.030014)
		(end 317.64986 -219.859352)
		(width 0.18288)
		(layer "In2.Cu")
		(net "M_B_CPU0_SB_DQ<11>")
	)
	(segment
		(start 316.722506 -220.98508)
		(end 316.529466 -220.79204)
		(width 0.18288)
		(layer "In2.Cu")
		(net "M_B_CPU0_SB_DQ<11>")
	)
	(segment
		(start 304.062638 -221.786196)
		(end 303.578768 -221.302326)
		(width 0.18288)
		(layer "In2.Cu")
		(net "M_B_CPU0_SB_DQ<11>")
	)
	(segment
		(start 307.512466 -220.98762)
		(end 306.735226 -221.76486)
		(width 0.18288)
		(layer "In2.Cu")
		(net "M_B_CPU0_SB_DQ<11>")
	)
	(segment
		(start 303.578768 -220.783404)
		(end 303.351946 -220.556582)
		(width 0.18288)
		(layer "In2.Cu")
		(net "M_B_CPU0_SB_DQ<11>")
	)
	(segment
		(start 306.210716 -221.576138)
		(end 304.615342 -221.576138)
		(width 0.18288)
		(layer "In2.Cu")
		(net "M_B_CPU0_SB_DQ<11>")
	)
	(segment
		(start 317.031878 -220.98508)
		(end 316.722506 -220.98508)
		(width 0.18288)
		(layer "In2.Cu")
		(net "M_B_CPU0_SB_DQ<11>")
	)
	(segment
		(start 315.117226 -220.052392)
		(end 314.924186 -219.859352)
		(width 0.18288)
		(layer "In2.Cu")
		(net "M_B_CPU0_SB_DQ<11>")
	)
	(segment
		(start 303.351946 -220.556582)
		(end 303.10963 -220.556582)
		(width 0.18288)
		(layer "In2.Cu")
		(net "M_B_CPU0_SB_DQ<11>")
	)
	(segment
		(start 336.064606 -233.449622)
		(end 335.99628 -233.517948)
		(width 0.088646)
		(layer "In2.Cu")
		(net "M_B_CPU0_SB_DQ<11>")
	)
	(segment
		(start 315.823346 -220.781372)
		(end 315.619638 -220.98508)
		(width 0.18288)
		(layer "In2.Cu")
		(net "M_B_CPU0_SB_DQ<11>")
	)
	(segment
		(start 317.235586 -220.781372)
		(end 317.031878 -220.98508)
		(width 0.18288)
		(layer "In2.Cu")
		(net "M_B_CPU0_SB_DQ<11>")
	)
	(segment
		(start 338.08035 -233.247438)
		(end 337.67649 -233.01452)
		(width 0.088646)
		(layer "In2.Cu")
		(net "M_B_CPU0_SB_DQ<11>")
	)
	(segment
		(start 315.117226 -220.79204)
		(end 315.117226 -220.052392)
		(width 0.18288)
		(layer "In2.Cu")
		(net "M_B_CPU0_SB_DQ<11>")
	)
	(segment
		(start 300.362366 -220.882972)
		(end 299.620686 -220.882972)
		(width 0.18288)
		(layer "In2.Cu")
		(net "M_B_CPU0_SB_DQ<11>")
	)
	(segment
		(start 303.578768 -221.302326)
		(end 303.578768 -220.783404)
		(width 0.18288)
		(layer "In2.Cu")
		(net "M_B_CPU0_SB_DQ<11>")
	)
	(segment
		(start 306.399438 -221.76486)
		(end 306.210716 -221.576138)
		(width 0.18288)
		(layer "In2.Cu")
		(net "M_B_CPU0_SB_DQ<11>")
	)
	(segment
		(start 307.803804 -220.98762)
		(end 307.512466 -220.98762)
		(width 0.18288)
		(layer "In2.Cu")
		(net "M_B_CPU0_SB_DQ<11>")
	)
	(segment
		(start 332.326234 -233.590846)
		(end 331.950822 -233.590846)
		(width 0.088646)
		(layer "In2.Cu")
		(net "M_B_CPU0_SB_DQ<11>")
	)
	(segment
		(start 315.619638 -220.98508)
		(end 315.310266 -220.98508)
		(width 0.18288)
		(layer "In2.Cu")
		(net "M_B_CPU0_SB_DQ<11>")
	)
	(segment
		(start 302.81245 -220.853762)
		(end 302.372268 -220.853762)
		(width 0.18288)
		(layer "In2.Cu")
		(net "M_B_CPU0_SB_DQ<11>")
	)
	(segment
		(start 314.924186 -219.859352)
		(end 311.290208 -219.859352)
		(width 0.18288)
		(layer "In2.Cu")
		(net "M_B_CPU0_SB_DQ<11>")
	)
	(segment
		(start 316.311026 -219.391992)
		(end 316.016386 -219.391992)
		(width 0.18288)
		(layer "In2.Cu")
		(net "M_B_CPU0_SB_DQ<11>")
	)
	(segment
		(start 336.742532 -233.017822)
		(end 336.738722 -233.015536)
		(width 0.088646)
		(layer "In2.Cu")
		(net "M_B_CPU0_SB_DQ<11>")
	)
	(segment
		(start 336.748374 -233.021124)
		(end 336.742532 -233.017822)
		(width 0.088646)
		(layer "In2.Cu")
		(net "M_B_CPU0_SB_DQ<11>")
	)
	(segment
		(start 316.529466 -220.79204)
		(end 316.529466 -219.610432)
		(width 0.18288)
		(layer "In2.Cu")
		(net "M_B_CPU0_SB_DQ<11>")
	)
	(segment
		(start 300.54042 -220.704918)
		(end 300.362366 -220.882972)
		(width 0.18288)
		(layer "In2.Cu")
		(net "M_B_CPU0_SB_DQ<11>")
	)
	(segment
		(start 331.950822 -233.590846)
		(end 331.38999 -233.030014)
		(width 0.088646)
		(layer "In2.Cu")
		(net "M_B_CPU0_SB_DQ<11>")
	)
	(segment
		(start 315.823346 -219.585032)
		(end 315.823346 -220.781372)
		(width 0.18288)
		(layer "In2.Cu")
		(net "M_B_CPU0_SB_DQ<11>")
	)
	(segment
		(start 331.38999 -233.030014)
		(end 331.181964 -233.030014)
		(width 0.088646)
		(layer "In2.Cu")
		(net "M_B_CPU0_SB_DQ<11>")
	)
	(segment
		(start 302.223424 -220.704918)
		(end 300.54042 -220.704918)
		(width 0.18288)
		(layer "In2.Cu")
		(net "M_B_CPU0_SB_DQ<11>")
	)
	(segment
		(start 336.280506 -233.084878)
		(end 336.169762 -233.195622)
		(width 0.088646)
		(layer "In2.Cu")
		(net "M_B_CPU0_SB_DQ<11>")
	)
	(segment
		(start 331.181964 -233.030014)
		(end 330.820522 -233.030014)
		(width 0.18288)
		(layer "In2.Cu")
		(net "M_B_CPU0_SB_DQ<11>")
	)
	(segment
		(start 308.086252 -220.705172)
		(end 307.803804 -220.98762)
		(width 0.18288)
		(layer "In2.Cu")
		(net "M_B_CPU0_SB_DQ<11>")
	)
	(segment
		(start 311.290208 -219.859352)
		(end 310.444388 -220.705172)
		(width 0.18288)
		(layer "In2.Cu")
		(net "M_B_CPU0_SB_DQ<11>")
	)
	(segment
		(start 304.405284 -221.786196)
		(end 304.062638 -221.786196)
		(width 0.18288)
		(layer "In2.Cu")
		(net "M_B_CPU0_SB_DQ<11>")
	)
	(segment
		(start 299.620686 -220.882972)
		(end 299.004482 -220.266768)
		(width 0.18288)
		(layer "In2.Cu")
		(net "M_B_CPU0_SB_DQ<11>")
	)
	(segment
		(start 316.016386 -219.391992)
		(end 315.823346 -219.585032)
		(width 0.18288)
		(layer "In2.Cu")
		(net "M_B_CPU0_SB_DQ<11>")
	)
	(segment
		(start 317.235586 -220.052392)
		(end 317.235586 -220.781372)
		(width 0.18288)
		(layer "In2.Cu")
		(net "M_B_CPU0_SB_DQ<11>")
	)
	(segment
		(start 332.998064 -233.657902)
		(end 332.983332 -233.666538)
		(width 0.088646)
		(layer "In2.Cu")
		(net "M_B_CPU0_SB_DQ<11>")
	)
	(segment
		(start 316.529466 -219.610432)
		(end 316.311026 -219.391992)
		(width 0.18288)
		(layer "In2.Cu")
		(net "M_B_CPU0_SB_DQ<11>")
	)
	(segment
		(start 303.10963 -220.556582)
		(end 302.81245 -220.853762)
		(width 0.18288)
		(layer "In2.Cu")
		(net "M_B_CPU0_SB_DQ<11>")
	)
	(segment
		(start 304.615342 -221.576138)
		(end 304.405284 -221.786196)
		(width 0.18288)
		(layer "In2.Cu")
		(net "M_B_CPU0_SB_DQ<11>")
	)
	(segment
		(start 315.310266 -220.98508)
		(end 315.117226 -220.79204)
		(width 0.18288)
		(layer "In2.Cu")
		(net "M_B_CPU0_SB_DQ<11>")
	)
	(segment
		(start 335.802732 -233.666792)
		(end 335.802732 -233.666538)
		(width 0.088646)
		(layer "In2.Cu")
		(net "M_B_CPU0_SB_DQ<11>")
	)
	(segment
		(start 310.444388 -220.705172)
		(end 308.086252 -220.705172)
		(width 0.18288)
		(layer "In2.Cu")
		(net "M_B_CPU0_SB_DQ<11>")
	)
	(segment
		(start 306.735226 -221.76486)
		(end 306.399438 -221.76486)
		(width 0.18288)
		(layer "In2.Cu")
		(net "M_B_CPU0_SB_DQ<11>")
	)
	(segment
		(start 317.428626 -219.859352)
		(end 317.235586 -220.052392)
		(width 0.18288)
		(layer "In2.Cu")
		(net "M_B_CPU0_SB_DQ<11>")
	)
	(segment
		(start 317.64986 -219.859352)
		(end 317.428626 -219.859352)
		(width 0.18288)
		(layer "In2.Cu")
		(net "M_B_CPU0_SB_DQ<11>")
	)
	(arc
		(start 338.43468 -233.34218)
		(mid 338.251287 -233.318093)
		(end 338.08035 -233.247438)
		(width 0.088646)
		(layer "In2.Cu")
		(net "M_B_CPU0_SB_DQ<11>")
	)
	(arc
		(start 335.802732 -233.666538)
		(mid 335.615534 -233.716681)
		(end 335.428336 -233.666538)
		(width 0.088646)
		(layer "In2.Cu")
		(net "M_B_CPU0_SB_DQ<11>")
	)
	(arc
		(start 336.738722 -233.015536)
		(mid 336.553003 -232.967584)
		(end 336.367882 -233.017822)
		(width 0.088646)
		(layer "In2.Cu")
		(net "M_B_CPU0_SB_DQ<11>")
	)
	(arc
		(start 333.923132 -233.666538)
		(mid 333.735934 -233.716681)
		(end 333.548736 -233.666538)
		(width 0.088646)
		(layer "In2.Cu")
		(net "M_B_CPU0_SB_DQ<11>")
	)
	(arc
		(start 333.548736 -233.666538)
		(mid 333.274507 -233.590613)
		(end 332.998064 -233.657902)
		(width 0.088646)
		(layer "In2.Cu")
		(net "M_B_CPU0_SB_DQ<11>")
	)
	(arc
		(start 334.862932 -233.666538)
		(mid 334.675734 -233.716681)
		(end 334.488536 -233.666538)
		(width 0.088646)
		(layer "In2.Cu")
		(net "M_B_CPU0_SB_DQ<11>")
	)
	(arc
		(start 337.307682 -233.017822)
		(mid 337.028479 -233.093462)
		(end 336.748374 -233.021124)
		(width 0.088646)
		(layer "In2.Cu")
		(net "M_B_CPU0_SB_DQ<11>")
	)
	(arc
		(start 334.488536 -233.666538)
		(mid 334.205834 -233.590796)
		(end 333.923132 -233.666538)
		(width 0.088646)
		(layer "In2.Cu")
		(net "M_B_CPU0_SB_DQ<11>")
	)
	(arc
		(start 332.983332 -233.666538)
		(mid 332.796134 -233.716681)
		(end 332.608936 -233.666538)
		(width 0.088646)
		(layer "In2.Cu")
		(net "M_B_CPU0_SB_DQ<11>")
	)
	(arc
		(start 336.10931 -233.341672)
		(mid 336.09769 -233.40009)
		(end 336.064606 -233.449622)
		(width 0.088646)
		(layer "In2.Cu")
		(net "M_B_CPU0_SB_DQ<11>")
	)
	(arc
		(start 337.67649 -233.01452)
		(mid 337.491635 -232.96757)
		(end 337.307682 -233.017822)
		(width 0.088646)
		(layer "In2.Cu")
		(net "M_B_CPU0_SB_DQ<11>")
	)
	(arc
		(start 335.99628 -233.517948)
		(mid 335.904361 -233.598684)
		(end 335.802732 -233.666792)
		(width 0.088646)
		(layer "In2.Cu")
		(net "M_B_CPU0_SB_DQ<11>")
	)
	(arc
		(start 336.169762 -233.195622)
		(mid 336.125042 -233.262645)
		(end 336.10931 -233.341672)
		(width 0.088646)
		(layer "In2.Cu")
		(net "M_B_CPU0_SB_DQ<11>")
	)
	(arc
		(start 336.367882 -233.017822)
		(mid 336.321991 -233.04848)
		(end 336.280506 -233.084878)
		(width 0.088646)
		(layer "In2.Cu")
		(net "M_B_CPU0_SB_DQ<11>")
	)
	(arc
		(start 332.608936 -233.666538)
		(mid 332.47257 -233.61006)
		(end 332.326234 -233.590846)
		(width 0.088646)
		(layer "In2.Cu")
		(net "M_B_CPU0_SB_DQ<11>")
	)
	(arc
		(start 335.428336 -233.666538)
		(mid 335.145634 -233.590796)
		(end 334.862932 -233.666538)
		(width 0.088646)
		(layer "In2.Cu")
		(net "M_B_CPU0_SB_DQ<11>")
	)
	(segment
		(start 295.633394 -221.541848)
		(end 295.000426 -221.541848)
		(width 0.20066)
		(layer "F.Cu")
		(net "M_B_CPU0_SB_DQ<10>")
	)
	(segment
		(start 337.96478 -234.69219)
		(end 337.965034 -234.691936)
		(width 0.20066)
		(layer "F.Cu")
		(net "M_B_CPU0_SB_DQ<10>")
	)
	(segment
		(start 292.68547 -221.541848)
		(end 292.67531 -221.531688)
		(width 0.101854)
		(layer "F.Cu")
		(net "M_B_CPU0_SB_DQ<10>")
	)
	(segment
		(start 297.899582 -221.96679)
		(end 296.584878 -221.96679)
		(width 0.20066)
		(layer "F.Cu")
		(net "M_B_CPU0_SB_DQ<10>")
	)
	(segment
		(start 295.777158 -222.01124)
		(end 295.777158 -221.685612)
		(width 0.20066)
		(layer "F.Cu")
		(net "M_B_CPU0_SB_DQ<10>")
	)
	(segment
		(start 295.777158 -221.685612)
		(end 295.633394 -221.541848)
		(width 0.20066)
		(layer "F.Cu")
		(net "M_B_CPU0_SB_DQ<10>")
	)
	(segment
		(start 291.937948 -221.531688)
		(end 291.502846 -221.96679)
		(width 0.20066)
		(layer "F.Cu")
		(net "M_B_CPU0_SB_DQ<10>")
	)
	(segment
		(start 337.965034 -234.691936)
		(end 337.965034 -234.15625)
		(width 0.20066)
		(layer "F.Cu")
		(net "M_B_CPU0_SB_DQ<10>")
	)
	(segment
		(start 295.000426 -221.541848)
		(end 292.940486 -221.541848)
		(width 0.1016)
		(layer "F.Cu")
		(net "M_B_CPU0_SB_DQ<10>")
	)
	(segment
		(start 291.502846 -221.96679)
		(end 290.355782 -221.96679)
		(width 0.20066)
		(layer "F.Cu")
		(net "M_B_CPU0_SB_DQ<10>")
	)
	(segment
		(start 292.67531 -221.531688)
		(end 291.937948 -221.531688)
		(width 0.20066)
		(layer "F.Cu")
		(net "M_B_CPU0_SB_DQ<10>")
	)
	(segment
		(start 296.584878 -221.96679)
		(end 296.373042 -222.178626)
		(width 0.20066)
		(layer "F.Cu")
		(net "M_B_CPU0_SB_DQ<10>")
	)
	(segment
		(start 292.940486 -221.541848)
		(end 292.68547 -221.541848)
		(width 0.101854)
		(layer "F.Cu")
		(net "M_B_CPU0_SB_DQ<10>")
	)
	(segment
		(start 299.004482 -221.96679)
		(end 297.899582 -221.96679)
		(width 0.20066)
		(layer "F.Cu")
		(net "M_B_CPU0_SB_DQ<10>")
	)
	(segment
		(start 296.373042 -222.178626)
		(end 295.944544 -222.178626)
		(width 0.20066)
		(layer "F.Cu")
		(net "M_B_CPU0_SB_DQ<10>")
	)
	(segment
		(start 295.944544 -222.178626)
		(end 295.777158 -222.01124)
		(width 0.20066)
		(layer "F.Cu")
		(net "M_B_CPU0_SB_DQ<10>")
	)
	(segment
		(start 305.929284 -222.920306)
		(end 304.946558 -222.920306)
		(width 0.18288)
		(layer "In2.Cu")
		(net "M_B_CPU0_SB_DQ<10>")
	)
	(segment
		(start 304.074576 -224.16008)
		(end 303.330356 -224.16008)
		(width 0.18288)
		(layer "In2.Cu")
		(net "M_B_CPU0_SB_DQ<10>")
	)
	(segment
		(start 302.87976 -223.709484)
		(end 302.87976 -223.436688)
		(width 0.18288)
		(layer "In2.Cu")
		(net "M_B_CPU0_SB_DQ<10>")
	)
	(segment
		(start 304.39487 -223.839786)
		(end 304.074576 -224.16008)
		(width 0.18288)
		(layer "In2.Cu")
		(net "M_B_CPU0_SB_DQ<10>")
	)
	(segment
		(start 307.082444 -223.46285)
		(end 306.471828 -223.46285)
		(width 0.18288)
		(layer "In2.Cu")
		(net "M_B_CPU0_SB_DQ<10>")
	)
	(segment
		(start 311.344056 -222.373444)
		(end 311.344056 -222.646748)
		(width 0.18288)
		(layer "In2.Cu")
		(net "M_B_CPU0_SB_DQ<10>")
	)
	(segment
		(start 331.828648 -234.404662)
		(end 331.470762 -234.046776)
		(width 0.088646)
		(layer "In2.Cu")
		(net "M_B_CPU0_SB_DQ<10>")
	)
	(segment
		(start 331.85608 -234.404662)
		(end 331.828648 -234.404662)
		(width 0.088646)
		(layer "In2.Cu")
		(net "M_B_CPU0_SB_DQ<10>")
	)
	(segment
		(start 335.347564 -234.471972)
		(end 335.332832 -234.480608)
		(width 0.088646)
		(layer "In2.Cu")
		(net "M_B_CPU0_SB_DQ<10>")
	)
	(segment
		(start 310.741568 -222.975932)
		(end 310.243728 -222.478092)
		(width 0.18288)
		(layer "In2.Cu")
		(net "M_B_CPU0_SB_DQ<10>")
	)
	(segment
		(start 310.983122 -222.01251)
		(end 311.344056 -222.373444)
		(width 0.18288)
		(layer "In2.Cu")
		(net "M_B_CPU0_SB_DQ<10>")
	)
	(segment
		(start 313.533028 -221.209108)
		(end 312.432954 -221.209108)
		(width 0.18288)
		(layer "In2.Cu")
		(net "M_B_CPU0_SB_DQ<10>")
	)
	(segment
		(start 310.243728 -222.478092)
		(end 309.88635 -222.478092)
		(width 0.18288)
		(layer "In2.Cu")
		(net "M_B_CPU0_SB_DQ<10>")
	)
	(segment
		(start 304.39487 -223.471994)
		(end 304.39487 -223.839786)
		(width 0.18288)
		(layer "In2.Cu")
		(net "M_B_CPU0_SB_DQ<10>")
	)
	(segment
		(start 314.262516 -221.546166)
		(end 313.870086 -221.546166)
		(width 0.18288)
		(layer "In2.Cu")
		(net "M_B_CPU0_SB_DQ<10>")
	)
	(segment
		(start 302.791622 -222.256096)
		(end 302.550068 -222.49765)
		(width 0.18288)
		(layer "In2.Cu")
		(net "M_B_CPU0_SB_DQ<10>")
	)
	(segment
		(start 301.867062 -222.08744)
		(end 300.782228 -222.08744)
		(width 0.18288)
		(layer "In2.Cu")
		(net "M_B_CPU0_SB_DQ<10>")
	)
	(segment
		(start 333.467964 -234.471972)
		(end 333.453232 -234.480608)
		(width 0.088646)
		(layer "In2.Cu")
		(net "M_B_CPU0_SB_DQ<10>")
	)
	(segment
		(start 310.983122 -221.739206)
		(end 310.983122 -222.01251)
		(width 0.18288)
		(layer "In2.Cu")
		(net "M_B_CPU0_SB_DQ<10>")
	)
	(segment
		(start 303.330356 -224.16008)
		(end 302.87976 -223.709484)
		(width 0.18288)
		(layer "In2.Cu")
		(net "M_B_CPU0_SB_DQ<10>")
	)
	(segment
		(start 312.432954 -221.209108)
		(end 312.095896 -221.546166)
		(width 0.18288)
		(layer "In2.Cu")
		(net "M_B_CPU0_SB_DQ<10>")
	)
	(segment
		(start 308.499256 -222.046038)
		(end 307.910738 -222.634556)
		(width 0.18288)
		(layer "In2.Cu")
		(net "M_B_CPU0_SB_DQ<10>")
	)
	(segment
		(start 336.460084 -234.148884)
		(end 336.460084 -234.161076)
		(width 0.088646)
		(layer "In2.Cu")
		(net "M_B_CPU0_SB_DQ<10>")
	)
	(segment
		(start 311.176162 -221.546166)
		(end 310.983122 -221.739206)
		(width 0.18288)
		(layer "In2.Cu")
		(net "M_B_CPU0_SB_DQ<10>")
	)
	(segment
		(start 332.528164 -234.471972)
		(end 332.513432 -234.480608)
		(width 0.088646)
		(layer "In2.Cu")
		(net "M_B_CPU0_SB_DQ<10>")
	)
	(segment
		(start 330.370688 -234.046776)
		(end 318.37757 -222.053658)
		(width 0.18288)
		(layer "In2.Cu")
		(net "M_B_CPU0_SB_DQ<10>")
	)
	(segment
		(start 334.407764 -234.471972)
		(end 334.393032 -234.480608)
		(width 0.088646)
		(layer "In2.Cu")
		(net "M_B_CPU0_SB_DQ<10>")
	)
	(segment
		(start 307.245258 -222.874332)
		(end 307.245258 -223.300036)
		(width 0.18288)
		(layer "In2.Cu")
		(net "M_B_CPU0_SB_DQ<10>")
	)
	(segment
		(start 311.014872 -222.975932)
		(end 310.741568 -222.975932)
		(width 0.18288)
		(layer "In2.Cu")
		(net "M_B_CPU0_SB_DQ<10>")
	)
	(segment
		(start 303.064926 -222.256096)
		(end 302.791622 -222.256096)
		(width 0.18288)
		(layer "In2.Cu")
		(net "M_B_CPU0_SB_DQ<10>")
	)
	(segment
		(start 307.485034 -222.634556)
		(end 307.245258 -222.874332)
		(width 0.18288)
		(layer "In2.Cu")
		(net "M_B_CPU0_SB_DQ<10>")
	)
	(segment
		(start 302.87976 -223.436688)
		(end 303.364138 -222.95231)
		(width 0.18288)
		(layer "In2.Cu")
		(net "M_B_CPU0_SB_DQ<10>")
	)
	(segment
		(start 303.364138 -222.555308)
		(end 303.064926 -222.256096)
		(width 0.18288)
		(layer "In2.Cu")
		(net "M_B_CPU0_SB_DQ<10>")
	)
	(segment
		(start 336.635852 -233.872532)
		(end 336.531204 -233.976926)
		(width 0.088646)
		(layer "In2.Cu")
		(net "M_B_CPU0_SB_DQ<10>")
	)
	(segment
		(start 309.454296 -222.046038)
		(end 308.499256 -222.046038)
		(width 0.18288)
		(layer "In2.Cu")
		(net "M_B_CPU0_SB_DQ<10>")
	)
	(segment
		(start 307.245258 -223.300036)
		(end 307.082444 -223.46285)
		(width 0.18288)
		(layer "In2.Cu")
		(net "M_B_CPU0_SB_DQ<10>")
	)
	(segment
		(start 309.88635 -222.478092)
		(end 309.454296 -222.046038)
		(width 0.18288)
		(layer "In2.Cu")
		(net "M_B_CPU0_SB_DQ<10>")
	)
	(segment
		(start 306.471828 -223.46285)
		(end 305.929284 -222.920306)
		(width 0.18288)
		(layer "In2.Cu")
		(net "M_B_CPU0_SB_DQ<10>")
	)
	(segment
		(start 314.770008 -222.053658)
		(end 314.262516 -221.546166)
		(width 0.18288)
		(layer "In2.Cu")
		(net "M_B_CPU0_SB_DQ<10>")
	)
	(segment
		(start 331.181964 -234.046776)
		(end 330.370688 -234.046776)
		(width 0.18288)
		(layer "In2.Cu")
		(net "M_B_CPU0_SB_DQ<10>")
	)
	(segment
		(start 311.344056 -222.646748)
		(end 311.014872 -222.975932)
		(width 0.18288)
		(layer "In2.Cu")
		(net "M_B_CPU0_SB_DQ<10>")
	)
	(segment
		(start 303.364138 -222.95231)
		(end 303.364138 -222.555308)
		(width 0.18288)
		(layer "In2.Cu")
		(net "M_B_CPU0_SB_DQ<10>")
	)
	(segment
		(start 304.946558 -222.920306)
		(end 304.39487 -223.471994)
		(width 0.18288)
		(layer "In2.Cu")
		(net "M_B_CPU0_SB_DQ<10>")
	)
	(segment
		(start 300.190408 -222.67926)
		(end 299.716952 -222.67926)
		(width 0.18288)
		(layer "In2.Cu")
		(net "M_B_CPU0_SB_DQ<10>")
	)
	(segment
		(start 299.716952 -222.67926)
		(end 299.004482 -221.96679)
		(width 0.18288)
		(layer "In2.Cu")
		(net "M_B_CPU0_SB_DQ<10>")
	)
	(segment
		(start 300.782228 -222.08744)
		(end 300.190408 -222.67926)
		(width 0.18288)
		(layer "In2.Cu")
		(net "M_B_CPU0_SB_DQ<10>")
	)
	(segment
		(start 302.277272 -222.49765)
		(end 301.867062 -222.08744)
		(width 0.18288)
		(layer "In2.Cu")
		(net "M_B_CPU0_SB_DQ<10>")
	)
	(segment
		(start 302.550068 -222.49765)
		(end 302.277272 -222.49765)
		(width 0.18288)
		(layer "In2.Cu")
		(net "M_B_CPU0_SB_DQ<10>")
	)
	(segment
		(start 312.095896 -221.546166)
		(end 311.176162 -221.546166)
		(width 0.18288)
		(layer "In2.Cu")
		(net "M_B_CPU0_SB_DQ<10>")
	)
	(segment
		(start 313.870086 -221.546166)
		(end 313.533028 -221.209108)
		(width 0.18288)
		(layer "In2.Cu")
		(net "M_B_CPU0_SB_DQ<10>")
	)
	(segment
		(start 337.965034 -234.15625)
		(end 337.578954 -233.841798)
		(width 0.088646)
		(layer "In2.Cu")
		(net "M_B_CPU0_SB_DQ<10>")
	)
	(segment
		(start 307.910738 -222.634556)
		(end 307.485034 -222.634556)
		(width 0.18288)
		(layer "In2.Cu")
		(net "M_B_CPU0_SB_DQ<10>")
	)
	(segment
		(start 331.470762 -234.046776)
		(end 331.181964 -234.046776)
		(width 0.088646)
		(layer "In2.Cu")
		(net "M_B_CPU0_SB_DQ<10>")
	)
	(segment
		(start 318.37757 -222.053658)
		(end 314.770008 -222.053658)
		(width 0.18288)
		(layer "In2.Cu")
		(net "M_B_CPU0_SB_DQ<10>")
	)
	(arc
		(start 332.139036 -234.480608)
		(mid 332.002564 -234.423985)
		(end 331.85608 -234.404662)
		(width 0.088646)
		(layer "In2.Cu")
		(net "M_B_CPU0_SB_DQ<10>")
	)
	(arc
		(start 337.578954 -233.841798)
		(mid 337.315864 -233.740805)
		(end 337.036156 -233.706416)
		(width 0.088646)
		(layer "In2.Cu")
		(net "M_B_CPU0_SB_DQ<10>")
	)
	(arc
		(start 333.453232 -234.480608)
		(mid 333.266034 -234.530751)
		(end 333.078836 -234.480608)
		(width 0.088646)
		(layer "In2.Cu")
		(net "M_B_CPU0_SB_DQ<10>")
	)
	(arc
		(start 336.272632 -234.480608)
		(mid 336.085434 -234.530751)
		(end 335.898236 -234.480608)
		(width 0.088646)
		(layer "In2.Cu")
		(net "M_B_CPU0_SB_DQ<10>")
	)
	(arc
		(start 333.078836 -234.480608)
		(mid 332.804637 -234.404773)
		(end 332.528164 -234.471972)
		(width 0.088646)
		(layer "In2.Cu")
		(net "M_B_CPU0_SB_DQ<10>")
	)
	(arc
		(start 335.332832 -234.480608)
		(mid 335.145634 -234.530751)
		(end 334.958436 -234.480608)
		(width 0.088646)
		(layer "In2.Cu")
		(net "M_B_CPU0_SB_DQ<10>")
	)
	(arc
		(start 337.036156 -233.706416)
		(mid 336.821146 -233.753674)
		(end 336.635852 -233.872532)
		(width 0.088646)
		(layer "In2.Cu")
		(net "M_B_CPU0_SB_DQ<10>")
	)
	(arc
		(start 336.460084 -234.161076)
		(mid 336.408595 -234.345615)
		(end 336.272632 -234.480608)
		(width 0.088646)
		(layer "In2.Cu")
		(net "M_B_CPU0_SB_DQ<10>")
	)
	(arc
		(start 336.531204 -233.976926)
		(mid 336.478488 -234.055821)
		(end 336.460084 -234.148884)
		(width 0.088646)
		(layer "In2.Cu")
		(net "M_B_CPU0_SB_DQ<10>")
	)
	(arc
		(start 334.018636 -234.480608)
		(mid 333.744437 -234.404773)
		(end 333.467964 -234.471972)
		(width 0.088646)
		(layer "In2.Cu")
		(net "M_B_CPU0_SB_DQ<10>")
	)
	(arc
		(start 332.513432 -234.480608)
		(mid 332.326234 -234.530751)
		(end 332.139036 -234.480608)
		(width 0.088646)
		(layer "In2.Cu")
		(net "M_B_CPU0_SB_DQ<10>")
	)
	(arc
		(start 335.898236 -234.480608)
		(mid 335.624037 -234.404773)
		(end 335.347564 -234.471972)
		(width 0.088646)
		(layer "In2.Cu")
		(net "M_B_CPU0_SB_DQ<10>")
	)
	(arc
		(start 334.393032 -234.480608)
		(mid 334.205834 -234.530751)
		(end 334.018636 -234.480608)
		(width 0.088646)
		(layer "In2.Cu")
		(net "M_B_CPU0_SB_DQ<10>")
	)
	(arc
		(start 334.958436 -234.480608)
		(mid 334.684237 -234.404773)
		(end 334.407764 -234.471972)
		(width 0.088646)
		(layer "In2.Cu")
		(net "M_B_CPU0_SB_DQ<10>")
	)
	(segment
		(start 292.430454 -232.166668)
		(end 292.005512 -231.741726)
		(width 0.20066)
		(layer "F.Cu")
		(net "M_B_CPU0_SB_DQ<0>")
	)
	(segment
		(start 291.556694 -231.741726)
		(end 289.48761 -231.741726)
		(width 0.1016)
		(layer "F.Cu")
		(net "M_B_CPU0_SB_DQ<0>")
	)
	(segment
		(start 288.46018 -232.232708)
		(end 288.28746 -232.405428)
		(width 0.20066)
		(layer "F.Cu")
		(net "M_B_CPU0_SB_DQ<0>")
	)
	(segment
		(start 292.005512 -231.741726)
		(end 291.556694 -231.741726)
		(width 0.20066)
		(layer "F.Cu")
		(net "M_B_CPU0_SB_DQ<0>")
	)
	(segment
		(start 288.46018 -231.943148)
		(end 288.46018 -232.232708)
		(width 0.20066)
		(layer "F.Cu")
		(net "M_B_CPU0_SB_DQ<0>")
	)
	(segment
		(start 287.828736 -232.405428)
		(end 287.589976 -232.166668)
		(width 0.20066)
		(layer "F.Cu")
		(net "M_B_CPU0_SB_DQ<0>")
	)
	(segment
		(start 289.239706 -231.741726)
		(end 289.231578 -231.733598)
		(width 0.101854)
		(layer "F.Cu")
		(net "M_B_CPU0_SB_DQ<0>")
	)
	(segment
		(start 294.904414 -232.166668)
		(end 293.799514 -232.166668)
		(width 0.20066)
		(layer "F.Cu")
		(net "M_B_CPU0_SB_DQ<0>")
	)
	(segment
		(start 340.31428 -237.133638)
		(end 340.31428 -236.597952)
		(width 0.20066)
		(layer "F.Cu")
		(net "M_B_CPU0_SB_DQ<0>")
	)
	(segment
		(start 293.799514 -232.166668)
		(end 292.430454 -232.166668)
		(width 0.20066)
		(layer "F.Cu")
		(net "M_B_CPU0_SB_DQ<0>")
	)
	(segment
		(start 289.231578 -231.733598)
		(end 288.66973 -231.733598)
		(width 0.20066)
		(layer "F.Cu")
		(net "M_B_CPU0_SB_DQ<0>")
	)
	(segment
		(start 288.66973 -231.733598)
		(end 288.46018 -231.943148)
		(width 0.20066)
		(layer "F.Cu")
		(net "M_B_CPU0_SB_DQ<0>")
	)
	(segment
		(start 289.48761 -231.741726)
		(end 289.239706 -231.741726)
		(width 0.101854)
		(layer "F.Cu")
		(net "M_B_CPU0_SB_DQ<0>")
	)
	(segment
		(start 288.28746 -232.405428)
		(end 287.828736 -232.405428)
		(width 0.20066)
		(layer "F.Cu")
		(net "M_B_CPU0_SB_DQ<0>")
	)
	(segment
		(start 340.314534 -237.133892)
		(end 340.31428 -237.133638)
		(width 0.20066)
		(layer "F.Cu")
		(net "M_B_CPU0_SB_DQ<0>")
	)
	(segment
		(start 287.589976 -232.166668)
		(end 286.255714 -232.166668)
		(width 0.20066)
		(layer "F.Cu")
		(net "M_B_CPU0_SB_DQ<0>")
	)
	(segment
		(start 339.187282 -236.92231)
		(end 339.187282 -236.922056)
		(width 0.088646)
		(layer "In4.Cu")
		(net "M_B_CPU0_SB_DQ<0>")
	)
	(segment
		(start 296.469054 -231.051862)
		(end 296.309034 -230.891842)
		(width 0.18288)
		(layer "In4.Cu")
		(net "M_B_CPU0_SB_DQ<0>")
	)
	(segment
		(start 297.32478 -230.891842)
		(end 297.16476 -231.051862)
		(width 0.18288)
		(layer "In4.Cu")
		(net "M_B_CPU0_SB_DQ<0>")
	)
	(segment
		(start 340.31428 -236.597952)
		(end 339.980778 -236.783626)
		(width 0.088646)
		(layer "In4.Cu")
		(net "M_B_CPU0_SB_DQ<0>")
	)
	(segment
		(start 306.925472 -230.213408)
		(end 306.637182 -229.925118)
		(width 0.18288)
		(layer "In4.Cu")
		(net "M_B_CPU0_SB_DQ<0>")
	)
	(segment
		(start 312.904632 -231.741472)
		(end 312.054748 -230.891842)
		(width 0.18288)
		(layer "In4.Cu")
		(net "M_B_CPU0_SB_DQ<0>")
	)
	(segment
		(start 295.4401 -231.62895)
		(end 295.441116 -231.629966)
		(width 0.18288)
		(layer "In4.Cu")
		(net "M_B_CPU0_SB_DQ<0>")
	)
	(segment
		(start 339.567774 -236.918754)
		(end 339.561932 -236.92231)
		(width 0.088646)
		(layer "In4.Cu")
		(net "M_B_CPU0_SB_DQ<0>")
	)
	(segment
		(start 311.52973 -230.891842)
		(end 311.35828 -231.063292)
		(width 0.18288)
		(layer "In4.Cu")
		(net "M_B_CPU0_SB_DQ<0>")
	)
	(segment
		(start 295.6433 -230.891842)
		(end 295.4401 -231.095042)
		(width 0.18288)
		(layer "In4.Cu")
		(net "M_B_CPU0_SB_DQ<0>")
	)
	(segment
		(start 332.522068 -237.731046)
		(end 332.513178 -237.736126)
		(width 0.088646)
		(layer "In4.Cu")
		(net "M_B_CPU0_SB_DQ<0>")
	)
	(segment
		(start 331.17536 -237.03407)
		(end 331.004164 -237.03407)
		(width 0.088646)
		(layer "In4.Cu")
		(net "M_B_CPU0_SB_DQ<0>")
	)
	(segment
		(start 301.182278 -230.32085)
		(end 301.035974 -230.467154)
		(width 0.18288)
		(layer "In4.Cu")
		(net "M_B_CPU0_SB_DQ<0>")
	)
	(segment
		(start 297.16476 -231.406192)
		(end 296.96791 -231.603042)
		(width 0.18288)
		(layer "In4.Cu")
		(net "M_B_CPU0_SB_DQ<0>")
	)
	(segment
		(start 339.561932 -236.92231)
		(end 339.55609 -236.925612)
		(width 0.088646)
		(layer "In4.Cu")
		(net "M_B_CPU0_SB_DQ<0>")
	)
	(segment
		(start 315.873892 -231.741472)
		(end 312.904632 -231.741472)
		(width 0.18288)
		(layer "In4.Cu")
		(net "M_B_CPU0_SB_DQ<0>")
	)
	(segment
		(start 303.171606 -230.32085)
		(end 301.182278 -230.32085)
		(width 0.18288)
		(layer "In4.Cu")
		(net "M_B_CPU0_SB_DQ<0>")
	)
	(segment
		(start 296.96791 -231.603042)
		(end 296.629074 -231.603042)
		(width 0.18288)
		(layer "In4.Cu")
		(net "M_B_CPU0_SB_DQ<0>")
	)
	(segment
		(start 296.309034 -230.891842)
		(end 295.6433 -230.891842)
		(width 0.18288)
		(layer "In4.Cu")
		(net "M_B_CPU0_SB_DQ<0>")
	)
	(segment
		(start 331.004164 -237.03407)
		(end 321.16649 -237.03407)
		(width 0.18288)
		(layer "In4.Cu")
		(net "M_B_CPU0_SB_DQ<0>")
	)
	(segment
		(start 295.4401 -231.095042)
		(end 295.4401 -231.62895)
		(width 0.18288)
		(layer "In4.Cu")
		(net "M_B_CPU0_SB_DQ<0>")
	)
	(segment
		(start 297.16476 -231.051862)
		(end 297.16476 -231.406192)
		(width 0.18288)
		(layer "In4.Cu")
		(net "M_B_CPU0_SB_DQ<0>")
	)
	(segment
		(start 305.613816 -229.925118)
		(end 304.526188 -231.012746)
		(width 0.18288)
		(layer "In4.Cu")
		(net "M_B_CPU0_SB_DQ<0>")
	)
	(segment
		(start 296.629074 -231.603042)
		(end 296.469054 -231.443022)
		(width 0.18288)
		(layer "In4.Cu")
		(net "M_B_CPU0_SB_DQ<0>")
	)
	(segment
		(start 301.035974 -230.467154)
		(end 299.672756 -230.467154)
		(width 0.18288)
		(layer "In4.Cu")
		(net "M_B_CPU0_SB_DQ<0>")
	)
	(segment
		(start 338.247482 -236.922056)
		(end 338.23275 -236.91342)
		(width 0.088646)
		(layer "In4.Cu")
		(net "M_B_CPU0_SB_DQ<0>")
	)
	(segment
		(start 295.441116 -231.629966)
		(end 294.904414 -232.166668)
		(width 0.18288)
		(layer "In4.Cu")
		(net "M_B_CPU0_SB_DQ<0>")
	)
	(segment
		(start 299.248068 -230.891842)
		(end 297.32478 -230.891842)
		(width 0.18288)
		(layer "In4.Cu")
		(net "M_B_CPU0_SB_DQ<0>")
	)
	(segment
		(start 299.672756 -230.467154)
		(end 299.248068 -230.891842)
		(width 0.18288)
		(layer "In4.Cu")
		(net "M_B_CPU0_SB_DQ<0>")
	)
	(segment
		(start 311.35828 -231.063292)
		(end 310.805322 -231.063292)
		(width 0.18288)
		(layer "In4.Cu")
		(net "M_B_CPU0_SB_DQ<0>")
	)
	(segment
		(start 303.863502 -231.012746)
		(end 303.171606 -230.32085)
		(width 0.18288)
		(layer "In4.Cu")
		(net "M_B_CPU0_SB_DQ<0>")
	)
	(segment
		(start 312.054748 -230.891842)
		(end 311.52973 -230.891842)
		(width 0.18288)
		(layer "In4.Cu")
		(net "M_B_CPU0_SB_DQ<0>")
	)
	(segment
		(start 331.801724 -237.660434)
		(end 331.17536 -237.03407)
		(width 0.088646)
		(layer "In4.Cu")
		(net "M_B_CPU0_SB_DQ<0>")
	)
	(segment
		(start 309.32501 -230.891842)
		(end 308.646576 -230.213408)
		(width 0.18288)
		(layer "In4.Cu")
		(net "M_B_CPU0_SB_DQ<0>")
	)
	(segment
		(start 308.646576 -230.213408)
		(end 306.925472 -230.213408)
		(width 0.18288)
		(layer "In4.Cu")
		(net "M_B_CPU0_SB_DQ<0>")
	)
	(segment
		(start 306.637182 -229.925118)
		(end 305.613816 -229.925118)
		(width 0.18288)
		(layer "In4.Cu")
		(net "M_B_CPU0_SB_DQ<0>")
	)
	(segment
		(start 339.187282 -236.922056)
		(end 339.17255 -236.91342)
		(width 0.088646)
		(layer "In4.Cu")
		(net "M_B_CPU0_SB_DQ<0>")
	)
	(segment
		(start 334.877664 -236.913674)
		(end 334.862932 -236.92231)
		(width 0.088646)
		(layer "In4.Cu")
		(net "M_B_CPU0_SB_DQ<0>")
	)
	(segment
		(start 310.633872 -230.891842)
		(end 309.32501 -230.891842)
		(width 0.18288)
		(layer "In4.Cu")
		(net "M_B_CPU0_SB_DQ<0>")
	)
	(segment
		(start 335.802732 -236.922056)
		(end 335.79181 -236.928406)
		(width 0.088646)
		(layer "In4.Cu")
		(net "M_B_CPU0_SB_DQ<0>")
	)
	(segment
		(start 337.307682 -236.922056)
		(end 337.297268 -236.91596)
		(width 0.088646)
		(layer "In4.Cu")
		(net "M_B_CPU0_SB_DQ<0>")
	)
	(segment
		(start 304.526188 -231.012746)
		(end 303.863502 -231.012746)
		(width 0.18288)
		(layer "In4.Cu")
		(net "M_B_CPU0_SB_DQ<0>")
	)
	(segment
		(start 296.469054 -231.443022)
		(end 296.469054 -231.051862)
		(width 0.18288)
		(layer "In4.Cu")
		(net "M_B_CPU0_SB_DQ<0>")
	)
	(segment
		(start 321.16649 -237.03407)
		(end 315.873892 -231.741472)
		(width 0.18288)
		(layer "In4.Cu")
		(net "M_B_CPU0_SB_DQ<0>")
	)
	(segment
		(start 332.998064 -236.913674)
		(end 332.983332 -236.92231)
		(width 0.088646)
		(layer "In4.Cu")
		(net "M_B_CPU0_SB_DQ<0>")
	)
	(segment
		(start 332.983332 -236.92231)
		(end 332.977236 -236.925866)
		(width 0.088646)
		(layer "In4.Cu")
		(net "M_B_CPU0_SB_DQ<0>")
	)
	(segment
		(start 310.805322 -231.063292)
		(end 310.633872 -230.891842)
		(width 0.18288)
		(layer "In4.Cu")
		(net "M_B_CPU0_SB_DQ<0>")
	)
	(segment
		(start 331.856588 -237.660434)
		(end 331.801724 -237.660434)
		(width 0.088646)
		(layer "In4.Cu")
		(net "M_B_CPU0_SB_DQ<0>")
	)
	(arc
		(start 336.742532 -236.922056)
		(mid 336.555334 -236.972233)
		(end 336.368136 -236.922056)
		(width 0.088646)
		(layer "In4.Cu")
		(net "M_B_CPU0_SB_DQ<0>")
	)
	(arc
		(start 338.621878 -236.922056)
		(mid 338.43468 -236.972233)
		(end 338.247482 -236.922056)
		(width 0.088646)
		(layer "In4.Cu")
		(net "M_B_CPU0_SB_DQ<0>")
	)
	(arc
		(start 336.368136 -236.922056)
		(mid 336.085434 -236.84628)
		(end 335.802732 -236.922056)
		(width 0.088646)
		(layer "In4.Cu")
		(net "M_B_CPU0_SB_DQ<0>")
	)
	(arc
		(start 334.488536 -236.92231)
		(mid 334.205834 -236.846534)
		(end 333.923132 -236.92231)
		(width 0.088646)
		(layer "In4.Cu")
		(net "M_B_CPU0_SB_DQ<0>")
	)
	(arc
		(start 332.70063 -237.411768)
		(mid 332.652951 -237.594668)
		(end 332.522068 -237.731046)
		(width 0.088646)
		(layer "In4.Cu")
		(net "M_B_CPU0_SB_DQ<0>")
	)
	(arc
		(start 339.980778 -236.783626)
		(mid 339.881147 -236.827092)
		(end 339.775038 -236.850682)
		(width 0.088646)
		(layer "In4.Cu")
		(net "M_B_CPU0_SB_DQ<0>")
	)
	(arc
		(start 333.923132 -236.92231)
		(mid 333.735934 -236.972453)
		(end 333.548736 -236.92231)
		(width 0.088646)
		(layer "In4.Cu")
		(net "M_B_CPU0_SB_DQ<0>")
	)
	(arc
		(start 335.79181 -236.928406)
		(mid 335.60928 -236.97243)
		(end 335.428336 -236.92231)
		(width 0.088646)
		(layer "In4.Cu")
		(net "M_B_CPU0_SB_DQ<0>")
	)
	(arc
		(start 334.862932 -236.92231)
		(mid 334.675734 -236.972453)
		(end 334.488536 -236.92231)
		(width 0.088646)
		(layer "In4.Cu")
		(net "M_B_CPU0_SB_DQ<0>")
	)
	(arc
		(start 332.513178 -237.736126)
		(mid 332.32598 -237.786269)
		(end 332.138782 -237.736126)
		(width 0.088646)
		(layer "In4.Cu")
		(net "M_B_CPU0_SB_DQ<0>")
	)
	(arc
		(start 337.297268 -236.91596)
		(mid 337.01909 -236.846237)
		(end 336.742532 -236.922056)
		(width 0.088646)
		(layer "In4.Cu")
		(net "M_B_CPU0_SB_DQ<0>")
	)
	(arc
		(start 339.775038 -236.850682)
		(mid 339.668087 -236.874614)
		(end 339.567774 -236.918754)
		(width 0.088646)
		(layer "In4.Cu")
		(net "M_B_CPU0_SB_DQ<0>")
	)
	(arc
		(start 335.428336 -236.92231)
		(mid 335.154137 -236.846475)
		(end 334.877664 -236.913674)
		(width 0.088646)
		(layer "In4.Cu")
		(net "M_B_CPU0_SB_DQ<0>")
	)
	(arc
		(start 339.17255 -236.91342)
		(mid 338.896075 -236.8461)
		(end 338.621878 -236.922056)
		(width 0.088646)
		(layer "In4.Cu")
		(net "M_B_CPU0_SB_DQ<0>")
	)
	(arc
		(start 337.682078 -236.922056)
		(mid 337.49488 -236.972233)
		(end 337.307682 -236.922056)
		(width 0.088646)
		(layer "In4.Cu")
		(net "M_B_CPU0_SB_DQ<0>")
	)
	(arc
		(start 332.138782 -237.736126)
		(mid 332.020151 -237.684606)
		(end 331.89291 -237.66145)
		(width 0.088646)
		(layer "In4.Cu")
		(net "M_B_CPU0_SB_DQ<0>")
	)
	(arc
		(start 331.89291 -237.66145)
		(mid 331.874757 -237.660647)
		(end 331.856588 -237.660434)
		(width 0.088646)
		(layer "In4.Cu")
		(net "M_B_CPU0_SB_DQ<0>")
	)
	(arc
		(start 339.55609 -236.925612)
		(mid 339.371235 -236.972562)
		(end 339.187282 -236.92231)
		(width 0.088646)
		(layer "In4.Cu")
		(net "M_B_CPU0_SB_DQ<0>")
	)
	(arc
		(start 333.548736 -236.92231)
		(mid 333.274537 -236.846475)
		(end 332.998064 -236.913674)
		(width 0.088646)
		(layer "In4.Cu")
		(net "M_B_CPU0_SB_DQ<0>")
	)
	(arc
		(start 332.977236 -236.925866)
		(mid 332.774649 -237.132217)
		(end 332.70063 -237.411768)
		(width 0.088646)
		(layer "In4.Cu")
		(net "M_B_CPU0_SB_DQ<0>")
	)
	(arc
		(start 338.23275 -236.91342)
		(mid 337.956275 -236.8461)
		(end 337.682078 -236.922056)
		(width 0.088646)
		(layer "In4.Cu")
		(net "M_B_CPU0_SB_DQ<0>")
	)
	(segment
		(start 337.96478 -246.08663)
		(end 337.965034 -246.086376)
		(width 0.20066)
		(layer "F.Cu")
		(net "M_B_CPU0_SB_CS_N<3>")
	)
	(segment
		(start 299.004482 -244.916706)
		(end 297.899582 -244.916706)
		(width 0.20066)
		(layer "F.Cu")
		(net "M_B_CPU0_SB_CS_N<3>")
	)
	(segment
		(start 337.965034 -246.086376)
		(end 337.965034 -245.55069)
		(width 0.20066)
		(layer "F.Cu")
		(net "M_B_CPU0_SB_CS_N<3>")
	)
	(segment
		(start 303.088294 -243.711476)
		(end 303.088294 -244.33149)
		(width 0.18288)
		(layer "In2.Cu")
		(net "M_B_CPU0_SB_CS_N<3>")
	)
	(segment
		(start 332.528164 -245.234968)
		(end 332.513432 -245.226332)
		(width 0.088646)
		(layer "In2.Cu")
		(net "M_B_CPU0_SB_CS_N<3>")
	)
	(segment
		(start 301.81423 -244.731032)
		(end 300.744636 -244.731032)
		(width 0.18288)
		(layer "In2.Cu")
		(net "M_B_CPU0_SB_CS_N<3>")
	)
	(segment
		(start 331.85608 -245.302278)
		(end 331.701648 -245.302278)
		(width 0.088646)
		(layer "In2.Cu")
		(net "M_B_CPU0_SB_CS_N<3>")
	)
	(segment
		(start 321.204082 -245.528846)
		(end 321.02806 -245.704868)
		(width 0.18288)
		(layer "In2.Cu")
		(net "M_B_CPU0_SB_CS_N<3>")
	)
	(segment
		(start 304.037746 -244.543072)
		(end 303.871122 -244.376448)
		(width 0.18288)
		(layer "In2.Cu")
		(net "M_B_CPU0_SB_CS_N<3>")
	)
	(segment
		(start 300.744636 -244.731032)
		(end 300.29277 -244.279166)
		(width 0.18288)
		(layer "In2.Cu")
		(net "M_B_CPU0_SB_CS_N<3>")
	)
	(segment
		(start 314.67171 -244.332252)
		(end 314.67171 -244.627146)
		(width 0.18288)
		(layer "In2.Cu")
		(net "M_B_CPU0_SB_CS_N<3>")
	)
	(segment
		(start 321.02806 -245.704868)
		(end 320.18224 -245.704868)
		(width 0.18288)
		(layer "In2.Cu")
		(net "M_B_CPU0_SB_CS_N<3>")
	)
	(segment
		(start 307.814472 -244.043454)
		(end 307.654452 -243.883434)
		(width 0.18288)
		(layer "In2.Cu")
		(net "M_B_CPU0_SB_CS_N<3>")
	)
	(segment
		(start 306.836572 -244.499384)
		(end 306.147978 -244.499384)
		(width 0.18288)
		(layer "In2.Cu")
		(net "M_B_CPU0_SB_CS_N<3>")
	)
	(segment
		(start 335.898236 -245.226332)
		(end 335.883504 -245.234968)
		(width 0.088646)
		(layer "In2.Cu")
		(net "M_B_CPU0_SB_CS_N<3>")
	)
	(segment
		(start 303.871122 -244.376448)
		(end 303.871122 -243.704872)
		(width 0.18288)
		(layer "In2.Cu")
		(net "M_B_CPU0_SB_CS_N<3>")
	)
	(segment
		(start 333.467964 -245.234968)
		(end 333.453232 -245.226332)
		(width 0.088646)
		(layer "In2.Cu")
		(net "M_B_CPU0_SB_CS_N<3>")
	)
	(segment
		(start 315.653928 -244.820186)
		(end 315.460888 -244.627146)
		(width 0.18288)
		(layer "In2.Cu")
		(net "M_B_CPU0_SB_CS_N<3>")
	)
	(segment
		(start 331.701648 -245.302278)
		(end 331.47508 -245.528846)
		(width 0.088646)
		(layer "In2.Cu")
		(net "M_B_CPU0_SB_CS_N<3>")
	)
	(segment
		(start 331.098906 -245.528846)
		(end 321.204082 -245.528846)
		(width 0.18288)
		(layer "In2.Cu")
		(net "M_B_CPU0_SB_CS_N<3>")
	)
	(segment
		(start 299.466508 -243.77523)
		(end 299.466508 -244.45468)
		(width 0.18288)
		(layer "In2.Cu")
		(net "M_B_CPU0_SB_CS_N<3>")
	)
	(segment
		(start 299.466508 -244.45468)
		(end 299.004482 -244.916706)
		(width 0.18288)
		(layer "In2.Cu")
		(net "M_B_CPU0_SB_CS_N<3>")
	)
	(segment
		(start 320.18224 -245.704868)
		(end 319.297558 -244.820186)
		(width 0.18288)
		(layer "In2.Cu")
		(net "M_B_CPU0_SB_CS_N<3>")
	)
	(segment
		(start 307.814472 -244.298978)
		(end 307.814472 -244.043454)
		(width 0.18288)
		(layer "In2.Cu")
		(net "M_B_CPU0_SB_CS_N<3>")
	)
	(segment
		(start 303.711102 -243.544852)
		(end 303.254918 -243.544852)
		(width 0.18288)
		(layer "In2.Cu")
		(net "M_B_CPU0_SB_CS_N<3>")
	)
	(segment
		(start 300.13275 -243.58219)
		(end 299.659548 -243.58219)
		(width 0.18288)
		(layer "In2.Cu")
		(net "M_B_CPU0_SB_CS_N<3>")
	)
	(segment
		(start 303.871122 -243.704872)
		(end 303.711102 -243.544852)
		(width 0.18288)
		(layer "In2.Cu")
		(net "M_B_CPU0_SB_CS_N<3>")
	)
	(segment
		(start 304.861722 -244.383052)
		(end 304.701702 -244.543072)
		(width 0.18288)
		(layer "In2.Cu")
		(net "M_B_CPU0_SB_CS_N<3>")
	)
	(segment
		(start 303.088294 -244.33149)
		(end 302.928274 -244.49151)
		(width 0.18288)
		(layer "In2.Cu")
		(net "M_B_CPU0_SB_CS_N<3>")
	)
	(segment
		(start 336.838036 -245.875048)
		(end 336.552032 -245.709694)
		(width 0.088646)
		(layer "In2.Cu")
		(net "M_B_CPU0_SB_CS_N<3>")
	)
	(segment
		(start 319.297558 -244.820186)
		(end 315.653928 -244.820186)
		(width 0.18288)
		(layer "In2.Cu")
		(net "M_B_CPU0_SB_CS_N<3>")
	)
	(segment
		(start 312.094118 -244.55374)
		(end 311.472326 -244.55374)
		(width 0.18288)
		(layer "In2.Cu")
		(net "M_B_CPU0_SB_CS_N<3>")
	)
	(segment
		(start 300.29277 -243.74221)
		(end 300.13275 -243.58219)
		(width 0.18288)
		(layer "In2.Cu")
		(net "M_B_CPU0_SB_CS_N<3>")
	)
	(segment
		(start 309.3085 -244.49151)
		(end 308.959758 -244.840252)
		(width 0.18288)
		(layer "In2.Cu")
		(net "M_B_CPU0_SB_CS_N<3>")
	)
	(segment
		(start 307.654452 -243.883434)
		(end 307.198268 -243.883434)
		(width 0.18288)
		(layer "In2.Cu")
		(net "M_B_CPU0_SB_CS_N<3>")
	)
	(segment
		(start 307.198268 -243.883434)
		(end 307.038248 -244.043454)
		(width 0.18288)
		(layer "In2.Cu")
		(net "M_B_CPU0_SB_CS_N<3>")
	)
	(segment
		(start 337.965034 -245.55069)
		(end 337.587082 -245.657624)
		(width 0.088646)
		(layer "In2.Cu")
		(net "M_B_CPU0_SB_CS_N<3>")
	)
	(segment
		(start 305.978306 -243.871242)
		(end 305.78552 -243.678456)
		(width 0.18288)
		(layer "In2.Cu")
		(net "M_B_CPU0_SB_CS_N<3>")
	)
	(segment
		(start 305.978306 -244.329712)
		(end 305.978306 -243.871242)
		(width 0.18288)
		(layer "In2.Cu")
		(net "M_B_CPU0_SB_CS_N<3>")
	)
	(segment
		(start 303.254918 -243.544852)
		(end 303.088294 -243.711476)
		(width 0.18288)
		(layer "In2.Cu")
		(net "M_B_CPU0_SB_CS_N<3>")
	)
	(segment
		(start 310.308498 -244.49151)
		(end 309.3085 -244.49151)
		(width 0.18288)
		(layer "In2.Cu")
		(net "M_B_CPU0_SB_CS_N<3>")
	)
	(segment
		(start 305.78552 -243.678456)
		(end 305.021742 -243.678456)
		(width 0.18288)
		(layer "In2.Cu")
		(net "M_B_CPU0_SB_CS_N<3>")
	)
	(segment
		(start 336.272632 -245.226586)
		(end 336.272632 -245.226332)
		(width 0.088646)
		(layer "In2.Cu")
		(net "M_B_CPU0_SB_CS_N<3>")
	)
	(segment
		(start 310.625236 -244.174772)
		(end 310.308498 -244.49151)
		(width 0.18288)
		(layer "In2.Cu")
		(net "M_B_CPU0_SB_CS_N<3>")
	)
	(segment
		(start 311.472326 -244.55374)
		(end 311.093358 -244.174772)
		(width 0.18288)
		(layer "In2.Cu")
		(net "M_B_CPU0_SB_CS_N<3>")
	)
	(segment
		(start 314.86475 -244.139212)
		(end 314.67171 -244.332252)
		(width 0.18288)
		(layer "In2.Cu")
		(net "M_B_CPU0_SB_CS_N<3>")
	)
	(segment
		(start 311.093358 -244.174772)
		(end 310.625236 -244.174772)
		(width 0.18288)
		(layer "In2.Cu")
		(net "M_B_CPU0_SB_CS_N<3>")
	)
	(segment
		(start 315.267848 -244.139212)
		(end 314.86475 -244.139212)
		(width 0.18288)
		(layer "In2.Cu")
		(net "M_B_CPU0_SB_CS_N<3>")
	)
	(segment
		(start 308.959758 -244.840252)
		(end 308.355746 -244.840252)
		(width 0.18288)
		(layer "In2.Cu")
		(net "M_B_CPU0_SB_CS_N<3>")
	)
	(segment
		(start 300.29277 -244.279166)
		(end 300.29277 -243.74221)
		(width 0.18288)
		(layer "In2.Cu")
		(net "M_B_CPU0_SB_CS_N<3>")
	)
	(segment
		(start 307.038248 -244.043454)
		(end 307.038248 -244.297708)
		(width 0.18288)
		(layer "In2.Cu")
		(net "M_B_CPU0_SB_CS_N<3>")
	)
	(segment
		(start 304.861722 -243.838476)
		(end 304.861722 -244.383052)
		(width 0.18288)
		(layer "In2.Cu")
		(net "M_B_CPU0_SB_CS_N<3>")
	)
	(segment
		(start 313.649868 -244.29085)
		(end 312.357008 -244.29085)
		(width 0.18288)
		(layer "In2.Cu")
		(net "M_B_CPU0_SB_CS_N<3>")
	)
	(segment
		(start 299.659548 -243.58219)
		(end 299.466508 -243.77523)
		(width 0.18288)
		(layer "In2.Cu")
		(net "M_B_CPU0_SB_CS_N<3>")
	)
	(segment
		(start 306.147978 -244.499384)
		(end 305.978306 -244.329712)
		(width 0.18288)
		(layer "In2.Cu")
		(net "M_B_CPU0_SB_CS_N<3>")
	)
	(segment
		(start 302.928274 -244.49151)
		(end 302.053752 -244.49151)
		(width 0.18288)
		(layer "In2.Cu")
		(net "M_B_CPU0_SB_CS_N<3>")
	)
	(segment
		(start 308.355746 -244.840252)
		(end 307.814472 -244.298978)
		(width 0.18288)
		(layer "In2.Cu")
		(net "M_B_CPU0_SB_CS_N<3>")
	)
	(segment
		(start 331.47508 -245.528846)
		(end 331.098906 -245.528846)
		(width 0.088646)
		(layer "In2.Cu")
		(net "M_B_CPU0_SB_CS_N<3>")
	)
	(segment
		(start 314.179204 -244.820186)
		(end 313.649868 -244.29085)
		(width 0.18288)
		(layer "In2.Cu")
		(net "M_B_CPU0_SB_CS_N<3>")
	)
	(segment
		(start 337.587082 -245.657624)
		(end 337.212432 -245.875048)
		(width 0.088646)
		(layer "In2.Cu")
		(net "M_B_CPU0_SB_CS_N<3>")
	)
	(segment
		(start 334.958436 -245.226332)
		(end 334.943704 -245.234968)
		(width 0.088646)
		(layer "In2.Cu")
		(net "M_B_CPU0_SB_CS_N<3>")
	)
	(segment
		(start 314.47867 -244.820186)
		(end 314.179204 -244.820186)
		(width 0.18288)
		(layer "In2.Cu")
		(net "M_B_CPU0_SB_CS_N<3>")
	)
	(segment
		(start 302.053752 -244.49151)
		(end 301.81423 -244.731032)
		(width 0.18288)
		(layer "In2.Cu")
		(net "M_B_CPU0_SB_CS_N<3>")
	)
	(segment
		(start 304.701702 -244.543072)
		(end 304.037746 -244.543072)
		(width 0.18288)
		(layer "In2.Cu")
		(net "M_B_CPU0_SB_CS_N<3>")
	)
	(segment
		(start 314.67171 -244.627146)
		(end 314.47867 -244.820186)
		(width 0.18288)
		(layer "In2.Cu")
		(net "M_B_CPU0_SB_CS_N<3>")
	)
	(segment
		(start 312.357008 -244.29085)
		(end 312.094118 -244.55374)
		(width 0.18288)
		(layer "In2.Cu")
		(net "M_B_CPU0_SB_CS_N<3>")
	)
	(segment
		(start 315.460888 -244.627146)
		(end 315.460888 -244.332252)
		(width 0.18288)
		(layer "In2.Cu")
		(net "M_B_CPU0_SB_CS_N<3>")
	)
	(segment
		(start 307.038248 -244.297708)
		(end 306.836572 -244.499384)
		(width 0.18288)
		(layer "In2.Cu")
		(net "M_B_CPU0_SB_CS_N<3>")
	)
	(segment
		(start 315.460888 -244.332252)
		(end 315.267848 -244.139212)
		(width 0.18288)
		(layer "In2.Cu")
		(net "M_B_CPU0_SB_CS_N<3>")
	)
	(segment
		(start 305.021742 -243.678456)
		(end 304.861722 -243.838476)
		(width 0.18288)
		(layer "In2.Cu")
		(net "M_B_CPU0_SB_CS_N<3>")
	)
	(arc
		(start 334.393032 -245.226332)
		(mid 334.205834 -245.176189)
		(end 334.018636 -245.226332)
		(width 0.088646)
		(layer "In2.Cu")
		(net "M_B_CPU0_SB_CS_N<3>")
	)
	(arc
		(start 336.460084 -245.55069)
		(mid 336.409791 -245.363514)
		(end 336.272632 -245.226586)
		(width 0.088646)
		(layer "In2.Cu")
		(net "M_B_CPU0_SB_CS_N<3>")
	)
	(arc
		(start 334.943704 -245.234968)
		(mid 334.667229 -245.302288)
		(end 334.393032 -245.226332)
		(width 0.088646)
		(layer "In2.Cu")
		(net "M_B_CPU0_SB_CS_N<3>")
	)
	(arc
		(start 337.212432 -245.875048)
		(mid 337.025234 -245.925225)
		(end 336.838036 -245.875048)
		(width 0.088646)
		(layer "In2.Cu")
		(net "M_B_CPU0_SB_CS_N<3>")
	)
	(arc
		(start 332.139036 -245.226332)
		(mid 332.002563 -245.282966)
		(end 331.85608 -245.302278)
		(width 0.088646)
		(layer "In2.Cu")
		(net "M_B_CPU0_SB_CS_N<3>")
	)
	(arc
		(start 335.332832 -245.226332)
		(mid 335.145634 -245.176189)
		(end 334.958436 -245.226332)
		(width 0.088646)
		(layer "In2.Cu")
		(net "M_B_CPU0_SB_CS_N<3>")
	)
	(arc
		(start 336.552032 -245.709694)
		(mid 336.484702 -245.642536)
		(end 336.460084 -245.55069)
		(width 0.088646)
		(layer "In2.Cu")
		(net "M_B_CPU0_SB_CS_N<3>")
	)
	(arc
		(start 332.513432 -245.226332)
		(mid 332.326234 -245.176189)
		(end 332.139036 -245.226332)
		(width 0.088646)
		(layer "In2.Cu")
		(net "M_B_CPU0_SB_CS_N<3>")
	)
	(arc
		(start 333.078836 -245.226332)
		(mid 332.804607 -245.302257)
		(end 332.528164 -245.234968)
		(width 0.088646)
		(layer "In2.Cu")
		(net "M_B_CPU0_SB_CS_N<3>")
	)
	(arc
		(start 334.018636 -245.226332)
		(mid 333.744407 -245.302257)
		(end 333.467964 -245.234968)
		(width 0.088646)
		(layer "In2.Cu")
		(net "M_B_CPU0_SB_CS_N<3>")
	)
	(arc
		(start 335.883504 -245.234968)
		(mid 335.607029 -245.302288)
		(end 335.332832 -245.226332)
		(width 0.088646)
		(layer "In2.Cu")
		(net "M_B_CPU0_SB_CS_N<3>")
	)
	(arc
		(start 333.453232 -245.226332)
		(mid 333.266034 -245.176189)
		(end 333.078836 -245.226332)
		(width 0.088646)
		(layer "In2.Cu")
		(net "M_B_CPU0_SB_CS_N<3>")
	)
	(arc
		(start 336.272632 -245.226332)
		(mid 336.085434 -245.176189)
		(end 335.898236 -245.226332)
		(width 0.088646)
		(layer "In2.Cu")
		(net "M_B_CPU0_SB_CS_N<3>")
	)
	(segment
		(start 294.904414 -245.76659)
		(end 293.799514 -245.76659)
		(width 0.20066)
		(layer "F.Cu")
		(net "M_B_CPU0_SB_CS_N<2>")
	)
	(segment
		(start 338.43468 -246.900192)
		(end 338.43468 -246.364506)
		(width 0.20066)
		(layer "F.Cu")
		(net "M_B_CPU0_SB_CS_N<2>")
	)
	(segment
		(start 338.434934 -246.900446)
		(end 338.43468 -246.900192)
		(width 0.20066)
		(layer "F.Cu")
		(net "M_B_CPU0_SB_CS_N<2>")
	)
	(segment
		(start 296.36593 -245.16461)
		(end 296.36593 -244.323108)
		(width 0.18288)
		(layer "In2.Cu")
		(net "M_B_CPU0_SB_CS_N<2>")
	)
	(segment
		(start 336.757264 -246.048784)
		(end 336.456274 -245.875048)
		(width 0.088646)
		(layer "In2.Cu")
		(net "M_B_CPU0_SB_CS_N<2>")
	)
	(segment
		(start 302.110648 -245.341648)
		(end 300.50359 -245.341648)
		(width 0.18288)
		(layer "In2.Cu")
		(net "M_B_CPU0_SB_CS_N<2>")
	)
	(segment
		(start 295.588182 -244.152166)
		(end 295.395142 -244.345206)
		(width 0.18288)
		(layer "In2.Cu")
		(net "M_B_CPU0_SB_CS_N<2>")
	)
	(segment
		(start 338.43468 -246.364506)
		(end 337.71078 -246.056658)
		(width 0.088646)
		(layer "In2.Cu")
		(net "M_B_CPU0_SB_CS_N<2>")
	)
	(segment
		(start 304.603658 -245.33098)
		(end 304.36185 -245.089172)
		(width 0.18288)
		(layer "In2.Cu")
		(net "M_B_CPU0_SB_CS_N<2>")
	)
	(segment
		(start 302.329342 -245.560342)
		(end 302.110648 -245.341648)
		(width 0.18288)
		(layer "In2.Cu")
		(net "M_B_CPU0_SB_CS_N<2>")
	)
	(segment
		(start 303.111154 -245.089172)
		(end 302.639984 -245.560342)
		(width 0.18288)
		(layer "In2.Cu")
		(net "M_B_CPU0_SB_CS_N<2>")
	)
	(segment
		(start 331.856334 -245.799356)
		(end 331.523848 -245.799356)
		(width 0.088646)
		(layer "In2.Cu")
		(net "M_B_CPU0_SB_CS_N<2>")
	)
	(segment
		(start 296.194988 -244.152166)
		(end 295.588182 -244.152166)
		(width 0.18288)
		(layer "In2.Cu")
		(net "M_B_CPU0_SB_CS_N<2>")
	)
	(segment
		(start 298.143168 -245.62308)
		(end 297.753532 -245.62308)
		(width 0.18288)
		(layer "In2.Cu")
		(net "M_B_CPU0_SB_CS_N<2>")
	)
	(segment
		(start 302.639984 -245.560342)
		(end 302.329342 -245.560342)
		(width 0.18288)
		(layer "In2.Cu")
		(net "M_B_CPU0_SB_CS_N<2>")
	)
	(segment
		(start 307.372004 -245.33098)
		(end 304.603658 -245.33098)
		(width 0.18288)
		(layer "In2.Cu")
		(net "M_B_CPU0_SB_CS_N<2>")
	)
	(segment
		(start 295.395142 -244.345206)
		(end 295.395142 -245.275862)
		(width 0.18288)
		(layer "In2.Cu")
		(net "M_B_CPU0_SB_CS_N<2>")
	)
	(segment
		(start 304.36185 -245.089172)
		(end 303.111154 -245.089172)
		(width 0.18288)
		(layer "In2.Cu")
		(net "M_B_CPU0_SB_CS_N<2>")
	)
	(segment
		(start 299.315378 -245.341648)
		(end 298.4246 -245.341648)
		(width 0.18288)
		(layer "In2.Cu")
		(net "M_B_CPU0_SB_CS_N<2>")
	)
	(segment
		(start 296.36593 -244.323108)
		(end 296.194988 -244.152166)
		(width 0.18288)
		(layer "In2.Cu")
		(net "M_B_CPU0_SB_CS_N<2>")
	)
	(segment
		(start 331.523848 -245.799356)
		(end 331.448918 -245.874286)
		(width 0.088646)
		(layer "In2.Cu")
		(net "M_B_CPU0_SB_CS_N<2>")
	)
	(segment
		(start 337.71078 -246.056658)
		(end 337.682332 -246.040148)
		(width 0.088646)
		(layer "In2.Cu")
		(net "M_B_CPU0_SB_CS_N<2>")
	)
	(segment
		(start 297.753532 -245.62308)
		(end 297.455082 -245.32463)
		(width 0.18288)
		(layer "In2.Cu")
		(net "M_B_CPU0_SB_CS_N<2>")
	)
	(segment
		(start 297.455082 -245.32463)
		(end 296.52595 -245.32463)
		(width 0.18288)
		(layer "In2.Cu")
		(net "M_B_CPU0_SB_CS_N<2>")
	)
	(segment
		(start 321.381374 -245.874286)
		(end 321.033394 -246.222266)
		(width 0.18288)
		(layer "In2.Cu")
		(net "M_B_CPU0_SB_CS_N<2>")
	)
	(segment
		(start 311.838594 -245.089172)
		(end 310.51627 -245.089172)
		(width 0.18288)
		(layer "In2.Cu")
		(net "M_B_CPU0_SB_CS_N<2>")
	)
	(segment
		(start 312.087514 -245.338092)
		(end 311.838594 -245.089172)
		(width 0.18288)
		(layer "In2.Cu")
		(net "M_B_CPU0_SB_CS_N<2>")
	)
	(segment
		(start 331.448918 -245.874286)
		(end 331.080364 -245.874286)
		(width 0.088646)
		(layer "In2.Cu")
		(net "M_B_CPU0_SB_CS_N<2>")
	)
	(segment
		(start 310.51627 -245.089172)
		(end 310.25338 -245.352062)
		(width 0.18288)
		(layer "In2.Cu")
		(net "M_B_CPU0_SB_CS_N<2>")
	)
	(segment
		(start 310.25338 -245.352062)
		(end 307.393086 -245.352062)
		(width 0.18288)
		(layer "In2.Cu")
		(net "M_B_CPU0_SB_CS_N<2>")
	)
	(segment
		(start 319.946782 -246.222266)
		(end 319.062608 -245.338092)
		(width 0.18288)
		(layer "In2.Cu")
		(net "M_B_CPU0_SB_CS_N<2>")
	)
	(segment
		(start 321.033394 -246.222266)
		(end 319.946782 -246.222266)
		(width 0.18288)
		(layer "In2.Cu")
		(net "M_B_CPU0_SB_CS_N<2>")
	)
	(segment
		(start 295.395142 -245.275862)
		(end 294.904414 -245.76659)
		(width 0.18288)
		(layer "In2.Cu")
		(net "M_B_CPU0_SB_CS_N<2>")
	)
	(segment
		(start 300.425612 -245.419626)
		(end 299.393356 -245.419626)
		(width 0.18288)
		(layer "In2.Cu")
		(net "M_B_CPU0_SB_CS_N<2>")
	)
	(segment
		(start 331.080364 -245.874286)
		(end 321.381374 -245.874286)
		(width 0.18288)
		(layer "In2.Cu")
		(net "M_B_CPU0_SB_CS_N<2>")
	)
	(segment
		(start 319.062608 -245.338092)
		(end 312.087514 -245.338092)
		(width 0.18288)
		(layer "In2.Cu")
		(net "M_B_CPU0_SB_CS_N<2>")
	)
	(segment
		(start 299.393356 -245.419626)
		(end 299.315378 -245.341648)
		(width 0.18288)
		(layer "In2.Cu")
		(net "M_B_CPU0_SB_CS_N<2>")
	)
	(segment
		(start 300.50359 -245.341648)
		(end 300.425612 -245.419626)
		(width 0.18288)
		(layer "In2.Cu")
		(net "M_B_CPU0_SB_CS_N<2>")
	)
	(segment
		(start 296.52595 -245.32463)
		(end 296.36593 -245.16461)
		(width 0.18288)
		(layer "In2.Cu")
		(net "M_B_CPU0_SB_CS_N<2>")
	)
	(segment
		(start 307.393086 -245.352062)
		(end 307.372004 -245.33098)
		(width 0.18288)
		(layer "In2.Cu")
		(net "M_B_CPU0_SB_CS_N<2>")
	)
	(segment
		(start 298.4246 -245.341648)
		(end 298.143168 -245.62308)
		(width 0.18288)
		(layer "In2.Cu")
		(net "M_B_CPU0_SB_CS_N<2>")
	)
	(arc
		(start 334.958436 -245.875048)
		(mid 334.675734 -245.799272)
		(end 334.393032 -245.875048)
		(width 0.088646)
		(layer "In2.Cu")
		(net "M_B_CPU0_SB_CS_N<2>")
	)
	(arc
		(start 335.898236 -245.875048)
		(mid 335.615534 -245.799272)
		(end 335.332832 -245.875048)
		(width 0.088646)
		(layer "In2.Cu")
		(net "M_B_CPU0_SB_CS_N<2>")
	)
	(arc
		(start 337.682332 -246.040148)
		(mid 337.503546 -245.990031)
		(end 337.322668 -246.03202)
		(width 0.088646)
		(layer "In2.Cu")
		(net "M_B_CPU0_SB_CS_N<2>")
	)
	(arc
		(start 334.393032 -245.875048)
		(mid 334.205834 -245.925191)
		(end 334.018636 -245.875048)
		(width 0.088646)
		(layer "In2.Cu")
		(net "M_B_CPU0_SB_CS_N<2>")
	)
	(arc
		(start 332.139036 -245.875048)
		(mid 332.002667 -245.818606)
		(end 331.856334 -245.799356)
		(width 0.088646)
		(layer "In2.Cu")
		(net "M_B_CPU0_SB_CS_N<2>")
	)
	(arc
		(start 337.322668 -246.03202)
		(mid 337.313713 -246.036726)
		(end 337.304888 -246.041672)
		(width 0.088646)
		(layer "In2.Cu")
		(net "M_B_CPU0_SB_CS_N<2>")
	)
	(arc
		(start 337.304888 -246.041672)
		(mid 337.032003 -246.115934)
		(end 336.757264 -246.048784)
		(width 0.088646)
		(layer "In2.Cu")
		(net "M_B_CPU0_SB_CS_N<2>")
	)
	(arc
		(start 336.456274 -245.875048)
		(mid 336.36447 -245.850504)
		(end 336.272632 -245.875048)
		(width 0.088646)
		(layer "In2.Cu")
		(net "M_B_CPU0_SB_CS_N<2>")
	)
	(arc
		(start 333.078836 -245.875048)
		(mid 332.796134 -245.799272)
		(end 332.513432 -245.875048)
		(width 0.088646)
		(layer "In2.Cu")
		(net "M_B_CPU0_SB_CS_N<2>")
	)
	(arc
		(start 335.332832 -245.875048)
		(mid 335.145634 -245.925191)
		(end 334.958436 -245.875048)
		(width 0.088646)
		(layer "In2.Cu")
		(net "M_B_CPU0_SB_CS_N<2>")
	)
	(arc
		(start 332.513432 -245.875048)
		(mid 332.326234 -245.925191)
		(end 332.139036 -245.875048)
		(width 0.088646)
		(layer "In2.Cu")
		(net "M_B_CPU0_SB_CS_N<2>")
	)
	(arc
		(start 336.272632 -245.875048)
		(mid 336.085434 -245.925225)
		(end 335.898236 -245.875048)
		(width 0.088646)
		(layer "In2.Cu")
		(net "M_B_CPU0_SB_CS_N<2>")
	)
	(arc
		(start 333.453232 -245.875048)
		(mid 333.266034 -245.925191)
		(end 333.078836 -245.875048)
		(width 0.088646)
		(layer "In2.Cu")
		(net "M_B_CPU0_SB_CS_N<2>")
	)
	(arc
		(start 334.018636 -245.875048)
		(mid 333.735934 -245.799272)
		(end 333.453232 -245.875048)
		(width 0.088646)
		(layer "In2.Cu")
		(net "M_B_CPU0_SB_CS_N<2>")
	)
	(segment
		(start 337.02498 -246.08663)
		(end 337.025234 -246.086376)
		(width 0.20066)
		(layer "F.Cu")
		(net "M_B_CPU0_SB_CS_N<1>")
	)
	(segment
		(start 337.025234 -246.086376)
		(end 337.025234 -245.55069)
		(width 0.20066)
		(layer "F.Cu")
		(net "M_B_CPU0_SB_CS_N<1>")
	)
	(segment
		(start 291.460682 -244.916706)
		(end 290.355782 -244.916706)
		(width 0.20066)
		(layer "F.Cu")
		(net "M_B_CPU0_SB_CS_N<1>")
	)
	(segment
		(start 318.14516 -243.811298)
		(end 318.14516 -244.100858)
		(width 0.18288)
		(layer "In2.Cu")
		(net "M_B_CPU0_SB_CS_N<1>")
	)
	(segment
		(start 312.26506 -243.778278)
		(end 312.128408 -243.641626)
		(width 0.18288)
		(layer "In2.Cu")
		(net "M_B_CPU0_SB_CS_N<1>")
	)
	(segment
		(start 292.128448 -244.24894)
		(end 291.460682 -244.916706)
		(width 0.18288)
		(layer "In2.Cu")
		(net "M_B_CPU0_SB_CS_N<1>")
	)
	(segment
		(start 332.608682 -245.060978)
		(end 332.59395 -245.052342)
		(width 0.088646)
		(layer "In2.Cu")
		(net "M_B_CPU0_SB_CS_N<1>")
	)
	(segment
		(start 300.663356 -242.12042)
		(end 300.155864 -241.612928)
		(width 0.18288)
		(layer "In2.Cu")
		(net "M_B_CPU0_SB_CS_N<1>")
	)
	(segment
		(start 295.44645 -242.793012)
		(end 294.146224 -242.793012)
		(width 0.18288)
		(layer "In2.Cu")
		(net "M_B_CPU0_SB_CS_N<1>")
	)
	(segment
		(start 333.548482 -245.060978)
		(end 333.53375 -245.052342)
		(width 0.088646)
		(layer "In2.Cu")
		(net "M_B_CPU0_SB_CS_N<1>")
	)
	(segment
		(start 316.910212 -243.618258)
		(end 316.717172 -243.811298)
		(width 0.18288)
		(layer "In2.Cu")
		(net "M_B_CPU0_SB_CS_N<1>")
	)
	(segment
		(start 336.382614 -245.069614)
		(end 336.35315 -245.052342)
		(width 0.088646)
		(layer "In2.Cu")
		(net "M_B_CPU0_SB_CS_N<1>")
	)
	(segment
		(start 293.378636 -242.51666)
		(end 293.378636 -242.12804)
		(width 0.18288)
		(layer "In2.Cu")
		(net "M_B_CPU0_SB_CS_N<1>")
	)
	(segment
		(start 318.848994 -243.618258)
		(end 318.3382 -243.618258)
		(width 0.18288)
		(layer "In2.Cu")
		(net "M_B_CPU0_SB_CS_N<1>")
	)
	(segment
		(start 313.736736 -243.778278)
		(end 312.26506 -243.778278)
		(width 0.18288)
		(layer "In2.Cu")
		(net "M_B_CPU0_SB_CS_N<1>")
	)
	(segment
		(start 292.128448 -242.85956)
		(end 292.321488 -243.0526)
		(width 0.18288)
		(layer "In2.Cu")
		(net "M_B_CPU0_SB_CS_N<1>")
	)
	(segment
		(start 292.321488 -243.0526)
		(end 292.63594 -243.0526)
		(width 0.18288)
		(layer "In2.Cu")
		(net "M_B_CPU0_SB_CS_N<1>")
	)
	(segment
		(start 300.155864 -241.612928)
		(end 299.882814 -241.612928)
		(width 0.18288)
		(layer "In2.Cu")
		(net "M_B_CPU0_SB_CS_N<1>")
	)
	(segment
		(start 315.975238 -243.811298)
		(end 315.782198 -243.618258)
		(width 0.18288)
		(layer "In2.Cu")
		(net "M_B_CPU0_SB_CS_N<1>")
	)
	(segment
		(start 307.188362 -242.920012)
		(end 306.89296 -243.215414)
		(width 0.18288)
		(layer "In2.Cu")
		(net "M_B_CPU0_SB_CS_N<1>")
	)
	(segment
		(start 292.82898 -243.56314)
		(end 292.63594 -243.75618)
		(width 0.18288)
		(layer "In2.Cu")
		(net "M_B_CPU0_SB_CS_N<1>")
	)
	(segment
		(start 306.703984 -243.215414)
		(end 306.280312 -242.791742)
		(width 0.18288)
		(layer "In2.Cu")
		(net "M_B_CPU0_SB_CS_N<1>")
	)
	(segment
		(start 303.982882 -242.791742)
		(end 303.789842 -242.598702)
		(width 0.18288)
		(layer "In2.Cu")
		(net "M_B_CPU0_SB_CS_N<1>")
	)
	(segment
		(start 334.877918 -245.052596)
		(end 334.863186 -245.061232)
		(width 0.088646)
		(layer "In2.Cu")
		(net "M_B_CPU0_SB_CS_N<1>")
	)
	(segment
		(start 333.923386 -245.061232)
		(end 333.922878 -245.060978)
		(width 0.088646)
		(layer "In2.Cu")
		(net "M_B_CPU0_SB_CS_N<1>")
	)
	(segment
		(start 318.14516 -244.100858)
		(end 317.95212 -244.293898)
		(width 0.18288)
		(layer "In2.Cu")
		(net "M_B_CPU0_SB_CS_N<1>")
	)
	(segment
		(start 302.974502 -242.136676)
		(end 302.974502 -242.631722)
		(width 0.18288)
		(layer "In2.Cu")
		(net "M_B_CPU0_SB_CS_N<1>")
	)
	(segment
		(start 293.378636 -242.12804)
		(end 293.178992 -241.928396)
		(width 0.18288)
		(layer "In2.Cu")
		(net "M_B_CPU0_SB_CS_N<1>")
	)
	(segment
		(start 317.95212 -244.293898)
		(end 317.617602 -244.293898)
		(width 0.18288)
		(layer "In2.Cu")
		(net "M_B_CPU0_SB_CS_N<1>")
	)
	(segment
		(start 301.371762 -242.12042)
		(end 300.663356 -242.12042)
		(width 0.18288)
		(layer "In2.Cu")
		(net "M_B_CPU0_SB_CS_N<1>")
	)
	(segment
		(start 307.41493 -242.920012)
		(end 307.188362 -242.920012)
		(width 0.18288)
		(layer "In2.Cu")
		(net "M_B_CPU0_SB_CS_N<1>")
	)
	(segment
		(start 315.975238 -244.110764)
		(end 315.975238 -243.811298)
		(width 0.18288)
		(layer "In2.Cu")
		(net "M_B_CPU0_SB_CS_N<1>")
	)
	(segment
		(start 331.616304 -245.112032)
		(end 331.54493 -245.183406)
		(width 0.088646)
		(layer "In2.Cu")
		(net "M_B_CPU0_SB_CS_N<1>")
	)
	(segment
		(start 317.424562 -244.100858)
		(end 317.424562 -243.811298)
		(width 0.18288)
		(layer "In2.Cu")
		(net "M_B_CPU0_SB_CS_N<1>")
	)
	(segment
		(start 303.134522 -241.976656)
		(end 302.974502 -242.136676)
		(width 0.18288)
		(layer "In2.Cu")
		(net "M_B_CPU0_SB_CS_N<1>")
	)
	(segment
		(start 296.881804 -242.89131)
		(end 296.688764 -243.08435)
		(width 0.18288)
		(layer "In2.Cu")
		(net "M_B_CPU0_SB_CS_N<1>")
	)
	(segment
		(start 316.168278 -244.303804)
		(end 315.975238 -244.110764)
		(width 0.18288)
		(layer "In2.Cu")
		(net "M_B_CPU0_SB_CS_N<1>")
	)
	(segment
		(start 315.782198 -243.618258)
		(end 313.896756 -243.618258)
		(width 0.18288)
		(layer "In2.Cu")
		(net "M_B_CPU0_SB_CS_N<1>")
	)
	(segment
		(start 303.623218 -241.976656)
		(end 303.134522 -241.976656)
		(width 0.18288)
		(layer "In2.Cu")
		(net "M_B_CPU0_SB_CS_N<1>")
	)
	(segment
		(start 331.54493 -245.183406)
		(end 331.080364 -245.183406)
		(width 0.088646)
		(layer "In2.Cu")
		(net "M_B_CPU0_SB_CS_N<1>")
	)
	(segment
		(start 299.882814 -241.612928)
		(end 299.553884 -241.941858)
		(width 0.18288)
		(layer "In2.Cu")
		(net "M_B_CPU0_SB_CS_N<1>")
	)
	(segment
		(start 320.414142 -245.183406)
		(end 318.848994 -243.618258)
		(width 0.18288)
		(layer "In2.Cu")
		(net "M_B_CPU0_SB_CS_N<1>")
	)
	(segment
		(start 301.691802 -242.791742)
		(end 301.531782 -242.631722)
		(width 0.18288)
		(layer "In2.Cu")
		(net "M_B_CPU0_SB_CS_N<1>")
	)
	(segment
		(start 301.531782 -242.631722)
		(end 301.531782 -242.28044)
		(width 0.18288)
		(layer "In2.Cu")
		(net "M_B_CPU0_SB_CS_N<1>")
	)
	(segment
		(start 313.896756 -243.618258)
		(end 313.736736 -243.778278)
		(width 0.18288)
		(layer "In2.Cu")
		(net "M_B_CPU0_SB_CS_N<1>")
	)
	(segment
		(start 296.688764 -243.08435)
		(end 295.737788 -243.08435)
		(width 0.18288)
		(layer "In2.Cu")
		(net "M_B_CPU0_SB_CS_N<1>")
	)
	(segment
		(start 292.128448 -243.94922)
		(end 292.128448 -244.24894)
		(width 0.18288)
		(layer "In2.Cu")
		(net "M_B_CPU0_SB_CS_N<1>")
	)
	(segment
		(start 306.280312 -242.791742)
		(end 303.982882 -242.791742)
		(width 0.18288)
		(layer "In2.Cu")
		(net "M_B_CPU0_SB_CS_N<1>")
	)
	(segment
		(start 317.424562 -243.811298)
		(end 317.231522 -243.618258)
		(width 0.18288)
		(layer "In2.Cu")
		(net "M_B_CPU0_SB_CS_N<1>")
	)
	(segment
		(start 303.789842 -242.598702)
		(end 303.789842 -242.14328)
		(width 0.18288)
		(layer "In2.Cu")
		(net "M_B_CPU0_SB_CS_N<1>")
	)
	(segment
		(start 317.231522 -243.618258)
		(end 316.910212 -243.618258)
		(width 0.18288)
		(layer "In2.Cu")
		(net "M_B_CPU0_SB_CS_N<1>")
	)
	(segment
		(start 297.041824 -241.941858)
		(end 296.881804 -242.101878)
		(width 0.18288)
		(layer "In2.Cu")
		(net "M_B_CPU0_SB_CS_N<1>")
	)
	(segment
		(start 308.136544 -243.641626)
		(end 307.41493 -242.920012)
		(width 0.18288)
		(layer "In2.Cu")
		(net "M_B_CPU0_SB_CS_N<1>")
	)
	(segment
		(start 296.881804 -242.101878)
		(end 296.881804 -242.89131)
		(width 0.18288)
		(layer "In2.Cu")
		(net "M_B_CPU0_SB_CS_N<1>")
	)
	(segment
		(start 318.3382 -243.618258)
		(end 318.14516 -243.811298)
		(width 0.18288)
		(layer "In2.Cu")
		(net "M_B_CPU0_SB_CS_N<1>")
	)
	(segment
		(start 336.397346 -245.077996)
		(end 336.382614 -245.069614)
		(width 0.088646)
		(layer "In2.Cu")
		(net "M_B_CPU0_SB_CS_N<1>")
	)
	(segment
		(start 299.553884 -241.941858)
		(end 297.041824 -241.941858)
		(width 0.18288)
		(layer "In2.Cu")
		(net "M_B_CPU0_SB_CS_N<1>")
	)
	(segment
		(start 331.85608 -245.112032)
		(end 331.616304 -245.112032)
		(width 0.088646)
		(layer "In2.Cu")
		(net "M_B_CPU0_SB_CS_N<1>")
	)
	(segment
		(start 333.938118 -245.052596)
		(end 333.923386 -245.061232)
		(width 0.088646)
		(layer "In2.Cu")
		(net "M_B_CPU0_SB_CS_N<1>")
	)
	(segment
		(start 306.89296 -243.215414)
		(end 306.703984 -243.215414)
		(width 0.18288)
		(layer "In2.Cu")
		(net "M_B_CPU0_SB_CS_N<1>")
	)
	(segment
		(start 335.802478 -245.060978)
		(end 335.802986 -245.061232)
		(width 0.088646)
		(layer "In2.Cu")
		(net "M_B_CPU0_SB_CS_N<1>")
	)
	(segment
		(start 292.321488 -243.75618)
		(end 292.128448 -243.94922)
		(width 0.18288)
		(layer "In2.Cu")
		(net "M_B_CPU0_SB_CS_N<1>")
	)
	(segment
		(start 312.128408 -243.641626)
		(end 308.136544 -243.641626)
		(width 0.18288)
		(layer "In2.Cu")
		(net "M_B_CPU0_SB_CS_N<1>")
	)
	(segment
		(start 302.814482 -242.791742)
		(end 301.691802 -242.791742)
		(width 0.18288)
		(layer "In2.Cu")
		(net "M_B_CPU0_SB_CS_N<1>")
	)
	(segment
		(start 293.538656 -242.67668)
		(end 293.378636 -242.51666)
		(width 0.18288)
		(layer "In2.Cu")
		(net "M_B_CPU0_SB_CS_N<1>")
	)
	(segment
		(start 316.717172 -244.110764)
		(end 316.524132 -244.303804)
		(width 0.18288)
		(layer "In2.Cu")
		(net "M_B_CPU0_SB_CS_N<1>")
	)
	(segment
		(start 292.63594 -243.0526)
		(end 292.82898 -243.24564)
		(width 0.18288)
		(layer "In2.Cu")
		(net "M_B_CPU0_SB_CS_N<1>")
	)
	(segment
		(start 292.361112 -241.928396)
		(end 292.128448 -242.16106)
		(width 0.18288)
		(layer "In2.Cu")
		(net "M_B_CPU0_SB_CS_N<1>")
	)
	(segment
		(start 294.029892 -242.67668)
		(end 293.538656 -242.67668)
		(width 0.18288)
		(layer "In2.Cu")
		(net "M_B_CPU0_SB_CS_N<1>")
	)
	(segment
		(start 294.146224 -242.793012)
		(end 294.029892 -242.67668)
		(width 0.18288)
		(layer "In2.Cu")
		(net "M_B_CPU0_SB_CS_N<1>")
	)
	(segment
		(start 337.025234 -245.55069)
		(end 336.397346 -245.077996)
		(width 0.088646)
		(layer "In2.Cu")
		(net "M_B_CPU0_SB_CS_N<1>")
	)
	(segment
		(start 292.128448 -242.16106)
		(end 292.128448 -242.85956)
		(width 0.18288)
		(layer "In2.Cu")
		(net "M_B_CPU0_SB_CS_N<1>")
	)
	(segment
		(start 331.080364 -245.183406)
		(end 320.414142 -245.183406)
		(width 0.18288)
		(layer "In2.Cu")
		(net "M_B_CPU0_SB_CS_N<1>")
	)
	(segment
		(start 302.974502 -242.631722)
		(end 302.814482 -242.791742)
		(width 0.18288)
		(layer "In2.Cu")
		(net "M_B_CPU0_SB_CS_N<1>")
	)
	(segment
		(start 316.524132 -244.303804)
		(end 316.168278 -244.303804)
		(width 0.18288)
		(layer "In2.Cu")
		(net "M_B_CPU0_SB_CS_N<1>")
	)
	(segment
		(start 316.717172 -243.811298)
		(end 316.717172 -244.110764)
		(width 0.18288)
		(layer "In2.Cu")
		(net "M_B_CPU0_SB_CS_N<1>")
	)
	(segment
		(start 292.63594 -243.75618)
		(end 292.321488 -243.75618)
		(width 0.18288)
		(layer "In2.Cu")
		(net "M_B_CPU0_SB_CS_N<1>")
	)
	(segment
		(start 301.531782 -242.28044)
		(end 301.371762 -242.12042)
		(width 0.18288)
		(layer "In2.Cu")
		(net "M_B_CPU0_SB_CS_N<1>")
	)
	(segment
		(start 317.617602 -244.293898)
		(end 317.424562 -244.100858)
		(width 0.18288)
		(layer "In2.Cu")
		(net "M_B_CPU0_SB_CS_N<1>")
	)
	(segment
		(start 295.737788 -243.08435)
		(end 295.44645 -242.793012)
		(width 0.18288)
		(layer "In2.Cu")
		(net "M_B_CPU0_SB_CS_N<1>")
	)
	(segment
		(start 303.789842 -242.14328)
		(end 303.623218 -241.976656)
		(width 0.18288)
		(layer "In2.Cu")
		(net "M_B_CPU0_SB_CS_N<1>")
	)
	(segment
		(start 293.178992 -241.928396)
		(end 292.361112 -241.928396)
		(width 0.18288)
		(layer "In2.Cu")
		(net "M_B_CPU0_SB_CS_N<1>")
	)
	(segment
		(start 292.82898 -243.24564)
		(end 292.82898 -243.56314)
		(width 0.18288)
		(layer "In2.Cu")
		(net "M_B_CPU0_SB_CS_N<1>")
	)
	(arc
		(start 334.48879 -245.061232)
		(mid 334.214591 -244.985397)
		(end 333.938118 -245.052596)
		(width 0.088646)
		(layer "In2.Cu")
		(net "M_B_CPU0_SB_CS_N<1>")
	)
	(arc
		(start 332.59395 -245.052342)
		(mid 332.317509 -244.985176)
		(end 332.043278 -245.060978)
		(width 0.088646)
		(layer "In2.Cu")
		(net "M_B_CPU0_SB_CS_N<1>")
	)
	(arc
		(start 334.863186 -245.061232)
		(mid 334.675988 -245.111375)
		(end 334.48879 -245.061232)
		(width 0.088646)
		(layer "In2.Cu")
		(net "M_B_CPU0_SB_CS_N<1>")
	)
	(arc
		(start 335.42859 -245.061232)
		(mid 335.154391 -244.985397)
		(end 334.877918 -245.052596)
		(width 0.088646)
		(layer "In2.Cu")
		(net "M_B_CPU0_SB_CS_N<1>")
	)
	(arc
		(start 335.802986 -245.061232)
		(mid 335.615788 -245.111375)
		(end 335.42859 -245.061232)
		(width 0.088646)
		(layer "In2.Cu")
		(net "M_B_CPU0_SB_CS_N<1>")
	)
	(arc
		(start 332.983078 -245.060978)
		(mid 332.79588 -245.111121)
		(end 332.608682 -245.060978)
		(width 0.088646)
		(layer "In2.Cu")
		(net "M_B_CPU0_SB_CS_N<1>")
	)
	(arc
		(start 332.043278 -245.060978)
		(mid 331.953042 -245.098848)
		(end 331.85608 -245.112032)
		(width 0.088646)
		(layer "In2.Cu")
		(net "M_B_CPU0_SB_CS_N<1>")
	)
	(arc
		(start 336.35315 -245.052342)
		(mid 336.076709 -244.985176)
		(end 335.802478 -245.060978)
		(width 0.088646)
		(layer "In2.Cu")
		(net "M_B_CPU0_SB_CS_N<1>")
	)
	(arc
		(start 333.53375 -245.052342)
		(mid 333.257309 -244.985176)
		(end 332.983078 -245.060978)
		(width 0.088646)
		(layer "In2.Cu")
		(net "M_B_CPU0_SB_CS_N<1>")
	)
	(arc
		(start 333.922878 -245.060978)
		(mid 333.73568 -245.111121)
		(end 333.548482 -245.060978)
		(width 0.088646)
		(layer "In2.Cu")
		(net "M_B_CPU0_SB_CS_N<1>")
	)
	(segment
		(start 287.360614 -245.76659)
		(end 286.255714 -245.76659)
		(width 0.20066)
		(layer "F.Cu")
		(net "M_B_CPU0_SB_CS_N<0>")
	)
	(segment
		(start 336.55508 -246.900192)
		(end 336.55508 -246.364506)
		(width 0.20066)
		(layer "F.Cu")
		(net "M_B_CPU0_SB_CS_N<0>")
	)
	(segment
		(start 336.555334 -246.900446)
		(end 336.55508 -246.900192)
		(width 0.20066)
		(layer "F.Cu")
		(net "M_B_CPU0_SB_CS_N<0>")
	)
	(segment
		(start 289.899344 -245.999)
		(end 289.706304 -246.19204)
		(width 0.18288)
		(layer "In2.Cu")
		(net "M_B_CPU0_SB_CS_N<0>")
	)
	(segment
		(start 308.327806 -246.515382)
		(end 307.983636 -246.171212)
		(width 0.18288)
		(layer "In2.Cu")
		(net "M_B_CPU0_SB_CS_N<0>")
	)
	(segment
		(start 335.831688 -246.057166)
		(end 335.802732 -246.040148)
		(width 0.088646)
		(layer "In2.Cu")
		(net "M_B_CPU0_SB_CS_N<0>")
	)
	(segment
		(start 290.737798 -245.999)
		(end 290.737798 -245.576852)
		(width 0.18288)
		(layer "In2.Cu")
		(net "M_B_CPU0_SB_CS_N<0>")
	)
	(segment
		(start 306.406042 -246.312944)
		(end 306.017168 -245.92407)
		(width 0.18288)
		(layer "In2.Cu")
		(net "M_B_CPU0_SB_CS_N<0>")
	)
	(segment
		(start 314.670186 -245.851934)
		(end 314.263024 -246.259096)
		(width 0.18288)
		(layer "In2.Cu")
		(net "M_B_CPU0_SB_CS_N<0>")
	)
	(segment
		(start 311.699148 -246.24411)
		(end 311.324752 -245.869714)
		(width 0.18288)
		(layer "In2.Cu")
		(net "M_B_CPU0_SB_CS_N<0>")
	)
	(segment
		(start 291.706046 -246.209312)
		(end 290.94811 -246.209312)
		(width 0.18288)
		(layer "In2.Cu")
		(net "M_B_CPU0_SB_CS_N<0>")
	)
	(segment
		(start 288.011108 -245.76659)
		(end 287.360614 -245.76659)
		(width 0.18288)
		(layer "In2.Cu")
		(net "M_B_CPU0_SB_CS_N<0>")
	)
	(segment
		(start 307.983636 -246.171212)
		(end 307.336698 -246.171212)
		(width 0.18288)
		(layer "In2.Cu")
		(net "M_B_CPU0_SB_CS_N<0>")
	)
	(segment
		(start 319.534032 -246.739918)
		(end 318.646048 -245.851934)
		(width 0.18288)
		(layer "In2.Cu")
		(net "M_B_CPU0_SB_CS_N<0>")
	)
	(segment
		(start 295.405048 -246.191532)
		(end 293.005764 -246.191532)
		(width 0.18288)
		(layer "In2.Cu")
		(net "M_B_CPU0_SB_CS_N<0>")
	)
	(segment
		(start 297.022774 -246.191532)
		(end 296.829734 -246.384572)
		(width 0.18288)
		(layer "In2.Cu")
		(net "M_B_CPU0_SB_CS_N<0>")
	)
	(segment
		(start 311.324752 -245.869714)
		(end 310.027574 -245.869714)
		(width 0.18288)
		(layer "In2.Cu")
		(net "M_B_CPU0_SB_CS_N<0>")
	)
	(segment
		(start 331.460602 -246.219726)
		(end 331.080618 -246.219726)
		(width 0.088646)
		(layer "In2.Cu")
		(net "M_B_CPU0_SB_CS_N<0>")
	)
	(segment
		(start 303.338738 -245.679976)
		(end 302.877728 -246.140986)
		(width 0.18288)
		(layer "In2.Cu")
		(net "M_B_CPU0_SB_CS_N<0>")
	)
	(segment
		(start 289.899344 -245.576852)
		(end 289.899344 -245.999)
		(width 0.18288)
		(layer "In2.Cu")
		(net "M_B_CPU0_SB_CS_N<0>")
	)
	(segment
		(start 295.598088 -246.384572)
		(end 295.405048 -246.191532)
		(width 0.18288)
		(layer "In2.Cu")
		(net "M_B_CPU0_SB_CS_N<0>")
	)
	(segment
		(start 290.544758 -245.383812)
		(end 290.092384 -245.383812)
		(width 0.18288)
		(layer "In2.Cu")
		(net "M_B_CPU0_SB_CS_N<0>")
	)
	(segment
		(start 296.636694 -247.03786)
		(end 295.791128 -247.03786)
		(width 0.18288)
		(layer "In2.Cu")
		(net "M_B_CPU0_SB_CS_N<0>")
	)
	(segment
		(start 295.791128 -247.03786)
		(end 295.598088 -246.84482)
		(width 0.18288)
		(layer "In2.Cu")
		(net "M_B_CPU0_SB_CS_N<0>")
	)
	(segment
		(start 310.027574 -245.869714)
		(end 309.381906 -246.515382)
		(width 0.18288)
		(layer "In2.Cu")
		(net "M_B_CPU0_SB_CS_N<0>")
	)
	(segment
		(start 296.829734 -246.84482)
		(end 296.636694 -247.03786)
		(width 0.18288)
		(layer "In2.Cu")
		(net "M_B_CPU0_SB_CS_N<0>")
	)
	(segment
		(start 290.092384 -245.383812)
		(end 289.899344 -245.576852)
		(width 0.18288)
		(layer "In2.Cu")
		(net "M_B_CPU0_SB_CS_N<0>")
	)
	(segment
		(start 321.238118 -246.739918)
		(end 319.534032 -246.739918)
		(width 0.18288)
		(layer "In2.Cu")
		(net "M_B_CPU0_SB_CS_N<0>")
	)
	(segment
		(start 299.202602 -246.191532)
		(end 297.022774 -246.191532)
		(width 0.18288)
		(layer "In2.Cu")
		(net "M_B_CPU0_SB_CS_N<0>")
	)
	(segment
		(start 309.381906 -246.515382)
		(end 308.327806 -246.515382)
		(width 0.18288)
		(layer "In2.Cu")
		(net "M_B_CPU0_SB_CS_N<0>")
	)
	(segment
		(start 302.877728 -246.140986)
		(end 300.45533 -246.140986)
		(width 0.18288)
		(layer "In2.Cu")
		(net "M_B_CPU0_SB_CS_N<0>")
	)
	(segment
		(start 290.737798 -245.576852)
		(end 290.544758 -245.383812)
		(width 0.18288)
		(layer "In2.Cu")
		(net "M_B_CPU0_SB_CS_N<0>")
	)
	(segment
		(start 307.336698 -246.171212)
		(end 307.194966 -246.312944)
		(width 0.18288)
		(layer "In2.Cu")
		(net "M_B_CPU0_SB_CS_N<0>")
	)
	(segment
		(start 289.466528 -246.19204)
		(end 289.306508 -246.35206)
		(width 0.18288)
		(layer "In2.Cu")
		(net "M_B_CPU0_SB_CS_N<0>")
	)
	(segment
		(start 307.194966 -246.312944)
		(end 306.406042 -246.312944)
		(width 0.18288)
		(layer "In2.Cu")
		(net "M_B_CPU0_SB_CS_N<0>")
	)
	(segment
		(start 300.45533 -246.140986)
		(end 300.287436 -245.973092)
		(width 0.18288)
		(layer "In2.Cu")
		(net "M_B_CPU0_SB_CS_N<0>")
	)
	(segment
		(start 288.215578 -245.97106)
		(end 288.011108 -245.76659)
		(width 0.18288)
		(layer "In2.Cu")
		(net "M_B_CPU0_SB_CS_N<0>")
	)
	(segment
		(start 295.598088 -246.84482)
		(end 295.598088 -246.384572)
		(width 0.18288)
		(layer "In2.Cu")
		(net "M_B_CPU0_SB_CS_N<0>")
	)
	(segment
		(start 304.141378 -246.202708)
		(end 303.618646 -245.679976)
		(width 0.18288)
		(layer "In2.Cu")
		(net "M_B_CPU0_SB_CS_N<0>")
	)
	(segment
		(start 291.978842 -245.936516)
		(end 291.706046 -246.209312)
		(width 0.18288)
		(layer "In2.Cu")
		(net "M_B_CPU0_SB_CS_N<0>")
	)
	(segment
		(start 288.408872 -247.047512)
		(end 288.215578 -246.854218)
		(width 0.18288)
		(layer "In2.Cu")
		(net "M_B_CPU0_SB_CS_N<0>")
	)
	(segment
		(start 304.848006 -245.92407)
		(end 304.569368 -246.202708)
		(width 0.18288)
		(layer "In2.Cu")
		(net "M_B_CPU0_SB_CS_N<0>")
	)
	(segment
		(start 336.55508 -246.364506)
		(end 336.55508 -246.364252)
		(width 0.088646)
		(layer "In2.Cu")
		(net "M_B_CPU0_SB_CS_N<0>")
	)
	(segment
		(start 292.750748 -245.936516)
		(end 291.978842 -245.936516)
		(width 0.18288)
		(layer "In2.Cu")
		(net "M_B_CPU0_SB_CS_N<0>")
	)
	(segment
		(start 318.646048 -245.851934)
		(end 314.670186 -245.851934)
		(width 0.18288)
		(layer "In2.Cu")
		(net "M_B_CPU0_SB_CS_N<0>")
	)
	(segment
		(start 289.306508 -246.86133)
		(end 289.120326 -247.047512)
		(width 0.18288)
		(layer "In2.Cu")
		(net "M_B_CPU0_SB_CS_N<0>")
	)
	(segment
		(start 289.306508 -246.35206)
		(end 289.306508 -246.86133)
		(width 0.18288)
		(layer "In2.Cu")
		(net "M_B_CPU0_SB_CS_N<0>")
	)
	(segment
		(start 288.215578 -246.854218)
		(end 288.215578 -245.97106)
		(width 0.18288)
		(layer "In2.Cu")
		(net "M_B_CPU0_SB_CS_N<0>")
	)
	(segment
		(start 304.569368 -246.202708)
		(end 304.141378 -246.202708)
		(width 0.18288)
		(layer "In2.Cu")
		(net "M_B_CPU0_SB_CS_N<0>")
	)
	(segment
		(start 289.706304 -246.19204)
		(end 289.466528 -246.19204)
		(width 0.18288)
		(layer "In2.Cu")
		(net "M_B_CPU0_SB_CS_N<0>")
	)
	(segment
		(start 331.080618 -246.219726)
		(end 321.75831 -246.219726)
		(width 0.18288)
		(layer "In2.Cu")
		(net "M_B_CPU0_SB_CS_N<0>")
	)
	(segment
		(start 321.75831 -246.219726)
		(end 321.238118 -246.739918)
		(width 0.18288)
		(layer "In2.Cu")
		(net "M_B_CPU0_SB_CS_N<0>")
	)
	(segment
		(start 303.618646 -245.679976)
		(end 303.338738 -245.679976)
		(width 0.18288)
		(layer "In2.Cu")
		(net "M_B_CPU0_SB_CS_N<0>")
	)
	(segment
		(start 313.558682 -245.851172)
		(end 312.469276 -245.851172)
		(width 0.18288)
		(layer "In2.Cu")
		(net "M_B_CPU0_SB_CS_N<0>")
	)
	(segment
		(start 331.856334 -245.989602)
		(end 331.690726 -245.989602)
		(width 0.088646)
		(layer "In2.Cu")
		(net "M_B_CPU0_SB_CS_N<0>")
	)
	(segment
		(start 296.829734 -246.384572)
		(end 296.829734 -246.84482)
		(width 0.18288)
		(layer "In2.Cu")
		(net "M_B_CPU0_SB_CS_N<0>")
	)
	(segment
		(start 290.94811 -246.209312)
		(end 290.737798 -245.999)
		(width 0.18288)
		(layer "In2.Cu")
		(net "M_B_CPU0_SB_CS_N<0>")
	)
	(segment
		(start 293.005764 -246.191532)
		(end 292.750748 -245.936516)
		(width 0.18288)
		(layer "In2.Cu")
		(net "M_B_CPU0_SB_CS_N<0>")
	)
	(segment
		(start 336.55508 -246.364252)
		(end 335.831688 -246.057166)
		(width 0.088646)
		(layer "In2.Cu")
		(net "M_B_CPU0_SB_CS_N<0>")
	)
	(segment
		(start 289.120326 -247.047512)
		(end 288.408872 -247.047512)
		(width 0.18288)
		(layer "In2.Cu")
		(net "M_B_CPU0_SB_CS_N<0>")
	)
	(segment
		(start 300.287436 -245.973092)
		(end 299.421042 -245.973092)
		(width 0.18288)
		(layer "In2.Cu")
		(net "M_B_CPU0_SB_CS_N<0>")
	)
	(segment
		(start 299.421042 -245.973092)
		(end 299.202602 -246.191532)
		(width 0.18288)
		(layer "In2.Cu")
		(net "M_B_CPU0_SB_CS_N<0>")
	)
	(segment
		(start 314.263024 -246.259096)
		(end 313.966606 -246.259096)
		(width 0.18288)
		(layer "In2.Cu")
		(net "M_B_CPU0_SB_CS_N<0>")
	)
	(segment
		(start 331.690726 -245.989602)
		(end 331.460602 -246.219726)
		(width 0.088646)
		(layer "In2.Cu")
		(net "M_B_CPU0_SB_CS_N<0>")
	)
	(segment
		(start 312.076338 -246.24411)
		(end 311.699148 -246.24411)
		(width 0.18288)
		(layer "In2.Cu")
		(net "M_B_CPU0_SB_CS_N<0>")
	)
	(segment
		(start 313.966606 -246.259096)
		(end 313.558682 -245.851172)
		(width 0.18288)
		(layer "In2.Cu")
		(net "M_B_CPU0_SB_CS_N<0>")
	)
	(segment
		(start 306.017168 -245.92407)
		(end 304.848006 -245.92407)
		(width 0.18288)
		(layer "In2.Cu")
		(net "M_B_CPU0_SB_CS_N<0>")
	)
	(segment
		(start 312.469276 -245.851172)
		(end 312.076338 -246.24411)
		(width 0.18288)
		(layer "In2.Cu")
		(net "M_B_CPU0_SB_CS_N<0>")
	)
	(arc
		(start 333.548736 -246.040148)
		(mid 333.266034 -246.115924)
		(end 332.983332 -246.040148)
		(width 0.088646)
		(layer "In2.Cu")
		(net "M_B_CPU0_SB_CS_N<0>")
	)
	(arc
		(start 333.923132 -246.040148)
		(mid 333.735934 -245.990005)
		(end 333.548736 -246.040148)
		(width 0.088646)
		(layer "In2.Cu")
		(net "M_B_CPU0_SB_CS_N<0>")
	)
	(arc
		(start 332.043532 -246.040148)
		(mid 331.95326 -246.002549)
		(end 331.856334 -245.989602)
		(width 0.088646)
		(layer "In2.Cu")
		(net "M_B_CPU0_SB_CS_N<0>")
	)
	(arc
		(start 335.428336 -246.040148)
		(mid 335.145634 -246.115924)
		(end 334.862932 -246.040148)
		(width 0.088646)
		(layer "In2.Cu")
		(net "M_B_CPU0_SB_CS_N<0>")
	)
	(arc
		(start 332.983332 -246.040148)
		(mid 332.796134 -245.990005)
		(end 332.608936 -246.040148)
		(width 0.088646)
		(layer "In2.Cu")
		(net "M_B_CPU0_SB_CS_N<0>")
	)
	(arc
		(start 335.802732 -246.040148)
		(mid 335.615534 -245.990005)
		(end 335.428336 -246.040148)
		(width 0.088646)
		(layer "In2.Cu")
		(net "M_B_CPU0_SB_CS_N<0>")
	)
	(arc
		(start 334.488536 -246.040148)
		(mid 334.205834 -246.115924)
		(end 333.923132 -246.040148)
		(width 0.088646)
		(layer "In2.Cu")
		(net "M_B_CPU0_SB_CS_N<0>")
	)
	(arc
		(start 334.862932 -246.040148)
		(mid 334.675734 -245.990005)
		(end 334.488536 -246.040148)
		(width 0.088646)
		(layer "In2.Cu")
		(net "M_B_CPU0_SB_CS_N<0>")
	)
	(arc
		(start 332.608936 -246.040148)
		(mid 332.326234 -246.115924)
		(end 332.043532 -246.040148)
		(width 0.088646)
		(layer "In2.Cu")
		(net "M_B_CPU0_SB_CS_N<0>")
	)
	(segment
		(start 338.434934 -243.644928)
		(end 338.43468 -243.644674)
		(width 0.20066)
		(layer "F.Cu")
		(net "M_B_CPU0_SB_CB<7>")
	)
	(segment
		(start 292.178994 -239.09274)
		(end 292.05301 -238.966756)
		(width 0.20066)
		(layer "F.Cu")
		(net "M_B_CPU0_SB_CB<7>")
	)
	(segment
		(start 295.544748 -239.391698)
		(end 295.000426 -239.391698)
		(width 0.20066)
		(layer "F.Cu")
		(net "M_B_CPU0_SB_CB<7>")
	)
	(segment
		(start 297.899582 -238.966756)
		(end 297.08348 -238.966756)
		(width 0.20066)
		(layer "F.Cu")
		(net "M_B_CPU0_SB_CB<7>")
	)
	(segment
		(start 296.217594 -238.962438)
		(end 295.82237 -238.962438)
		(width 0.20066)
		(layer "F.Cu")
		(net "M_B_CPU0_SB_CB<7>")
	)
	(segment
		(start 292.321488 -239.405922)
		(end 292.178994 -239.263428)
		(width 0.20066)
		(layer "F.Cu")
		(net "M_B_CPU0_SB_CB<7>")
	)
	(segment
		(start 292.178994 -239.263428)
		(end 292.178994 -239.09274)
		(width 0.20066)
		(layer "F.Cu")
		(net "M_B_CPU0_SB_CB<7>")
	)
	(segment
		(start 295.693846 -239.090962)
		(end 295.693846 -239.2426)
		(width 0.20066)
		(layer "F.Cu")
		(net "M_B_CPU0_SB_CB<7>")
	)
	(segment
		(start 296.875962 -239.174274)
		(end 296.42943 -239.174274)
		(width 0.20066)
		(layer "F.Cu")
		(net "M_B_CPU0_SB_CB<7>")
	)
	(segment
		(start 299.004482 -238.966756)
		(end 297.899582 -238.966756)
		(width 0.20066)
		(layer "F.Cu")
		(net "M_B_CPU0_SB_CB<7>")
	)
	(segment
		(start 295.82237 -238.962438)
		(end 295.693846 -239.090962)
		(width 0.20066)
		(layer "F.Cu")
		(net "M_B_CPU0_SB_CB<7>")
	)
	(segment
		(start 295.693846 -239.2426)
		(end 295.544748 -239.391698)
		(width 0.20066)
		(layer "F.Cu")
		(net "M_B_CPU0_SB_CB<7>")
	)
	(segment
		(start 292.05301 -238.966756)
		(end 290.355782 -238.966756)
		(width 0.20066)
		(layer "F.Cu")
		(net "M_B_CPU0_SB_CB<7>")
	)
	(segment
		(start 297.08348 -238.966756)
		(end 296.875962 -239.174274)
		(width 0.20066)
		(layer "F.Cu")
		(net "M_B_CPU0_SB_CB<7>")
	)
	(segment
		(start 292.927532 -239.391698)
		(end 292.689534 -239.391698)
		(width 0.101854)
		(layer "F.Cu")
		(net "M_B_CPU0_SB_CB<7>")
	)
	(segment
		(start 292.67531 -239.405922)
		(end 292.321488 -239.405922)
		(width 0.20066)
		(layer "F.Cu")
		(net "M_B_CPU0_SB_CB<7>")
	)
	(segment
		(start 292.689534 -239.391698)
		(end 292.67531 -239.405922)
		(width 0.101854)
		(layer "F.Cu")
		(net "M_B_CPU0_SB_CB<7>")
	)
	(segment
		(start 296.42943 -239.174274)
		(end 296.217594 -238.962438)
		(width 0.20066)
		(layer "F.Cu")
		(net "M_B_CPU0_SB_CB<7>")
	)
	(segment
		(start 338.43468 -243.644674)
		(end 338.43468 -243.108988)
		(width 0.20066)
		(layer "F.Cu")
		(net "M_B_CPU0_SB_CB<7>")
	)
	(segment
		(start 295.000426 -239.391698)
		(end 292.927532 -239.391698)
		(width 0.1016)
		(layer "F.Cu")
		(net "M_B_CPU0_SB_CB<7>")
	)
	(segment
		(start 317.522606 -240.378488)
		(end 317.329566 -240.185448)
		(width 0.18288)
		(layer "In2.Cu")
		(net "M_B_CPU0_SB_CB<7>")
	)
	(segment
		(start 316.487302 -239.669574)
		(end 316.074298 -239.498632)
		(width 0.18288)
		(layer "In2.Cu")
		(net "M_B_CPU0_SB_CB<7>")
	)
	(segment
		(start 302.446436 -238.253524)
		(end 301.922434 -238.777526)
		(width 0.18288)
		(layer "In2.Cu")
		(net "M_B_CPU0_SB_CB<7>")
	)
	(segment
		(start 311.217818 -239.978692)
		(end 311.024778 -240.171732)
		(width 0.18288)
		(layer "In2.Cu")
		(net "M_B_CPU0_SB_CB<7>")
	)
	(segment
		(start 314.790836 -239.098328)
		(end 314.142882 -239.098328)
		(width 0.18288)
		(layer "In2.Cu")
		(net "M_B_CPU0_SB_CB<7>")
	)
	(segment
		(start 312.25744 -239.49279)
		(end 311.860438 -239.095788)
		(width 0.18288)
		(layer "In2.Cu")
		(net "M_B_CPU0_SB_CB<7>")
	)
	(segment
		(start 309.523892 -240.398554)
		(end 308.218332 -240.398554)
		(width 0.18288)
		(layer "In2.Cu")
		(net "M_B_CPU0_SB_CB<7>")
	)
	(segment
		(start 318.272668 -240.78184)
		(end 318.272668 -241.42065)
		(width 0.18288)
		(layer "In2.Cu")
		(net "M_B_CPU0_SB_CB<7>")
	)
	(segment
		(start 337.869784 -243.544598)
		(end 337.781138 -243.596414)
		(width 0.088646)
		(layer "In2.Cu")
		(net "M_B_CPU0_SB_CB<7>")
	)
	(segment
		(start 311.217818 -239.288828)
		(end 311.217818 -239.978692)
		(width 0.18288)
		(layer "In2.Cu")
		(net "M_B_CPU0_SB_CB<7>")
	)
	(segment
		(start 318.465708 -240.5888)
		(end 318.272668 -240.78184)
		(width 0.18288)
		(layer "In2.Cu")
		(net "M_B_CPU0_SB_CB<7>")
	)
	(segment
		(start 311.410858 -239.095788)
		(end 311.217818 -239.288828)
		(width 0.18288)
		(layer "In2.Cu")
		(net "M_B_CPU0_SB_CB<7>")
	)
	(segment
		(start 306.675536 -239.400588)
		(end 306.366164 -239.400588)
		(width 0.18288)
		(layer "In2.Cu")
		(net "M_B_CPU0_SB_CB<7>")
	)
	(segment
		(start 318.079628 -241.61369)
		(end 317.715646 -241.61369)
		(width 0.18288)
		(layer "In2.Cu")
		(net "M_B_CPU0_SB_CB<7>")
	)
	(segment
		(start 310.789066 -240.171732)
		(end 310.605424 -239.98809)
		(width 0.18288)
		(layer "In2.Cu")
		(net "M_B_CPU0_SB_CB<7>")
	)
	(segment
		(start 315.007498 -239.276382)
		(end 314.790836 -239.098328)
		(width 0.18288)
		(layer "In2.Cu")
		(net "M_B_CPU0_SB_CB<7>")
	)
	(segment
		(start 300.737016 -238.777526)
		(end 300.360334 -238.400844)
		(width 0.18288)
		(layer "In2.Cu")
		(net "M_B_CPU0_SB_CB<7>")
	)
	(segment
		(start 299.489622 -238.966756)
		(end 299.004482 -238.966756)
		(width 0.18288)
		(layer "In2.Cu")
		(net "M_B_CPU0_SB_CB<7>")
	)
	(segment
		(start 316.75324 -240.185448)
		(end 316.558422 -239.99063)
		(width 0.18288)
		(layer "In2.Cu")
		(net "M_B_CPU0_SB_CB<7>")
	)
	(segment
		(start 317.329566 -240.185448)
		(end 316.75324 -240.185448)
		(width 0.18288)
		(layer "In2.Cu")
		(net "M_B_CPU0_SB_CB<7>")
	)
	(segment
		(start 336.836512 -243.599208)
		(end 336.827368 -243.604542)
		(width 0.088646)
		(layer "In2.Cu")
		(net "M_B_CPU0_SB_CB<7>")
	)
	(segment
		(start 300.360334 -238.400844)
		(end 300.055534 -238.400844)
		(width 0.18288)
		(layer "In2.Cu")
		(net "M_B_CPU0_SB_CB<7>")
	)
	(segment
		(start 319.171828 -241.61369)
		(end 318.978788 -241.42065)
		(width 0.18288)
		(layer "In2.Cu")
		(net "M_B_CPU0_SB_CB<7>")
	)
	(segment
		(start 316.558422 -239.776)
		(end 316.487302 -239.669574)
		(width 0.18288)
		(layer "In2.Cu")
		(net "M_B_CPU0_SB_CB<7>")
	)
	(segment
		(start 315.621416 -240.088928)
		(end 315.36894 -240.193576)
		(width 0.18288)
		(layer "In2.Cu")
		(net "M_B_CPU0_SB_CB<7>")
	)
	(segment
		(start 337.212432 -243.597684)
		(end 337.212432 -243.59743)
		(width 0.088646)
		(layer "In2.Cu")
		(net "M_B_CPU0_SB_CB<7>")
	)
	(segment
		(start 317.522606 -241.42065)
		(end 317.522606 -240.378488)
		(width 0.18288)
		(layer "In2.Cu")
		(net "M_B_CPU0_SB_CB<7>")
	)
	(segment
		(start 337.872832 -243.54282)
		(end 337.871308 -243.543582)
		(width 0.088646)
		(layer "In2.Cu")
		(net "M_B_CPU0_SB_CB<7>")
	)
	(segment
		(start 332.138782 -243.598446)
		(end 332.12405 -243.607082)
		(width 0.088646)
		(layer "In2.Cu")
		(net "M_B_CPU0_SB_CB<7>")
	)
	(segment
		(start 311.860438 -239.095788)
		(end 311.410858 -239.095788)
		(width 0.18288)
		(layer "In2.Cu")
		(net "M_B_CPU0_SB_CB<7>")
	)
	(segment
		(start 311.024778 -240.171732)
		(end 310.789066 -240.171732)
		(width 0.18288)
		(layer "In2.Cu")
		(net "M_B_CPU0_SB_CB<7>")
	)
	(segment
		(start 303.754282 -239.120172)
		(end 302.887634 -238.253524)
		(width 0.18288)
		(layer "In2.Cu")
		(net "M_B_CPU0_SB_CB<7>")
	)
	(segment
		(start 314.142882 -239.098328)
		(end 313.74842 -239.49279)
		(width 0.18288)
		(layer "In2.Cu")
		(net "M_B_CPU0_SB_CB<7>")
	)
	(segment
		(start 318.272668 -241.42065)
		(end 318.079628 -241.61369)
		(width 0.18288)
		(layer "In2.Cu")
		(net "M_B_CPU0_SB_CB<7>")
	)
	(segment
		(start 304.373026 -239.120172)
		(end 303.754282 -239.120172)
		(width 0.18288)
		(layer "In2.Cu")
		(net "M_B_CPU0_SB_CB<7>")
	)
	(segment
		(start 304.89525 -239.642396)
		(end 304.373026 -239.120172)
		(width 0.18288)
		(layer "In2.Cu")
		(net "M_B_CPU0_SB_CB<7>")
	)
	(segment
		(start 333.078582 -243.598446)
		(end 333.06385 -243.607082)
		(width 0.088646)
		(layer "In2.Cu")
		(net "M_B_CPU0_SB_CB<7>")
	)
	(segment
		(start 315.070744 -240.069878)
		(end 314.956698 -239.794034)
		(width 0.18288)
		(layer "In2.Cu")
		(net "M_B_CPU0_SB_CB<7>")
	)
	(segment
		(start 300.055534 -238.400844)
		(end 299.489622 -238.966756)
		(width 0.18288)
		(layer "In2.Cu")
		(net "M_B_CPU0_SB_CB<7>")
	)
	(segment
		(start 315.36894 -240.193576)
		(end 315.070744 -240.069878)
		(width 0.18288)
		(layer "In2.Cu")
		(net "M_B_CPU0_SB_CB<7>")
	)
	(segment
		(start 308.218332 -240.398554)
		(end 307.77815 -239.958372)
		(width 0.18288)
		(layer "In2.Cu")
		(net "M_B_CPU0_SB_CB<7>")
	)
	(segment
		(start 321.84721 -243.537486)
		(end 319.923414 -241.61369)
		(width 0.18288)
		(layer "In2.Cu")
		(net "M_B_CPU0_SB_CB<7>")
	)
	(segment
		(start 331.433932 -243.537486)
		(end 331.004164 -243.537486)
		(width 0.088646)
		(layer "In2.Cu")
		(net "M_B_CPU0_SB_CB<7>")
	)
	(segment
		(start 307.23332 -239.958372)
		(end 306.675536 -239.400588)
		(width 0.18288)
		(layer "In2.Cu")
		(net "M_B_CPU0_SB_CB<7>")
	)
	(segment
		(start 319.923414 -241.61369)
		(end 319.171828 -241.61369)
		(width 0.18288)
		(layer "In2.Cu")
		(net "M_B_CPU0_SB_CB<7>")
	)
	(segment
		(start 318.978788 -240.78184)
		(end 318.785748 -240.5888)
		(width 0.18288)
		(layer "In2.Cu")
		(net "M_B_CPU0_SB_CB<7>")
	)
	(segment
		(start 331.82433 -243.68252)
		(end 331.578966 -243.68252)
		(width 0.088646)
		(layer "In2.Cu")
		(net "M_B_CPU0_SB_CB<7>")
	)
	(segment
		(start 331.004164 -243.537486)
		(end 321.84721 -243.537486)
		(width 0.18288)
		(layer "In2.Cu")
		(net "M_B_CPU0_SB_CB<7>")
	)
	(segment
		(start 301.922434 -238.777526)
		(end 300.737016 -238.777526)
		(width 0.18288)
		(layer "In2.Cu")
		(net "M_B_CPU0_SB_CB<7>")
	)
	(segment
		(start 307.77815 -239.958372)
		(end 307.23332 -239.958372)
		(width 0.18288)
		(layer "In2.Cu")
		(net "M_B_CPU0_SB_CB<7>")
	)
	(segment
		(start 316.074298 -239.498632)
		(end 315.821822 -239.60328)
		(width 0.18288)
		(layer "In2.Cu")
		(net "M_B_CPU0_SB_CB<7>")
	)
	(segment
		(start 306.366164 -239.400588)
		(end 306.124356 -239.642396)
		(width 0.18288)
		(layer "In2.Cu")
		(net "M_B_CPU0_SB_CB<7>")
	)
	(segment
		(start 310.605424 -239.98809)
		(end 309.934356 -239.98809)
		(width 0.18288)
		(layer "In2.Cu")
		(net "M_B_CPU0_SB_CB<7>")
	)
	(segment
		(start 333.453232 -243.598446)
		(end 333.452978 -243.598446)
		(width 0.088646)
		(layer "In2.Cu")
		(net "M_B_CPU0_SB_CB<7>")
	)
	(segment
		(start 317.715646 -241.61369)
		(end 317.522606 -241.42065)
		(width 0.18288)
		(layer "In2.Cu")
		(net "M_B_CPU0_SB_CB<7>")
	)
	(segment
		(start 318.978788 -241.42065)
		(end 318.978788 -240.78184)
		(width 0.18288)
		(layer "In2.Cu")
		(net "M_B_CPU0_SB_CB<7>")
	)
	(segment
		(start 306.124356 -239.642396)
		(end 304.89525 -239.642396)
		(width 0.18288)
		(layer "In2.Cu")
		(net "M_B_CPU0_SB_CB<7>")
	)
	(segment
		(start 318.785748 -240.5888)
		(end 318.465708 -240.5888)
		(width 0.18288)
		(layer "In2.Cu")
		(net "M_B_CPU0_SB_CB<7>")
	)
	(segment
		(start 316.558422 -239.99063)
		(end 316.558422 -239.776)
		(width 0.18288)
		(layer "In2.Cu")
		(net "M_B_CPU0_SB_CB<7>")
	)
	(segment
		(start 315.821822 -239.60328)
		(end 315.621416 -240.088928)
		(width 0.18288)
		(layer "In2.Cu")
		(net "M_B_CPU0_SB_CB<7>")
	)
	(segment
		(start 309.934356 -239.98809)
		(end 309.523892 -240.398554)
		(width 0.18288)
		(layer "In2.Cu")
		(net "M_B_CPU0_SB_CB<7>")
	)
	(segment
		(start 315.060076 -239.54486)
		(end 315.007498 -239.276382)
		(width 0.18288)
		(layer "In2.Cu")
		(net "M_B_CPU0_SB_CB<7>")
	)
	(segment
		(start 313.74842 -239.49279)
		(end 312.25744 -239.49279)
		(width 0.18288)
		(layer "In2.Cu")
		(net "M_B_CPU0_SB_CB<7>")
	)
	(segment
		(start 331.578966 -243.68252)
		(end 331.433932 -243.537486)
		(width 0.088646)
		(layer "In2.Cu")
		(net "M_B_CPU0_SB_CB<7>")
	)
	(segment
		(start 302.887634 -238.253524)
		(end 302.446436 -238.253524)
		(width 0.18288)
		(layer "In2.Cu")
		(net "M_B_CPU0_SB_CB<7>")
	)
	(segment
		(start 336.272632 -243.598446)
		(end 336.272378 -243.598446)
		(width 0.088646)
		(layer "In2.Cu")
		(net "M_B_CPU0_SB_CB<7>")
	)
	(segment
		(start 314.956698 -239.794034)
		(end 315.060076 -239.54486)
		(width 0.18288)
		(layer "In2.Cu")
		(net "M_B_CPU0_SB_CB<7>")
	)
	(arc
		(start 337.781138 -243.596414)
		(mid 337.496949 -243.673764)
		(end 337.212432 -243.597684)
		(width 0.088646)
		(layer "In2.Cu")
		(net "M_B_CPU0_SB_CB<7>")
	)
	(arc
		(start 334.958436 -243.598446)
		(mid 334.675734 -243.674222)
		(end 334.393032 -243.598446)
		(width 0.088646)
		(layer "In2.Cu")
		(net "M_B_CPU0_SB_CB<7>")
	)
	(arc
		(start 332.12405 -243.607082)
		(mid 331.978859 -243.66334)
		(end 331.82433 -243.68252)
		(width 0.088646)
		(layer "In2.Cu")
		(net "M_B_CPU0_SB_CB<7>")
	)
	(arc
		(start 336.827368 -243.604542)
		(mid 336.54919 -243.674265)
		(end 336.272632 -243.598446)
		(width 0.088646)
		(layer "In2.Cu")
		(net "M_B_CPU0_SB_CB<7>")
	)
	(arc
		(start 337.871308 -243.543582)
		(mid 337.870543 -243.544086)
		(end 337.869784 -243.544598)
		(width 0.088646)
		(layer "In2.Cu")
		(net "M_B_CPU0_SB_CB<7>")
	)
	(arc
		(start 333.452978 -243.598446)
		(mid 333.26578 -243.548303)
		(end 333.078582 -243.598446)
		(width 0.088646)
		(layer "In2.Cu")
		(net "M_B_CPU0_SB_CB<7>")
	)
	(arc
		(start 336.272378 -243.598446)
		(mid 336.085324 -243.548396)
		(end 335.898236 -243.598446)
		(width 0.088646)
		(layer "In2.Cu")
		(net "M_B_CPU0_SB_CB<7>")
	)
	(arc
		(start 334.018636 -243.598446)
		(mid 333.735934 -243.674222)
		(end 333.453232 -243.598446)
		(width 0.088646)
		(layer "In2.Cu")
		(net "M_B_CPU0_SB_CB<7>")
	)
	(arc
		(start 334.393032 -243.598446)
		(mid 334.205834 -243.548303)
		(end 334.018636 -243.598446)
		(width 0.088646)
		(layer "In2.Cu")
		(net "M_B_CPU0_SB_CB<7>")
	)
	(arc
		(start 337.212432 -243.59743)
		(mid 337.024232 -243.547772)
		(end 336.836512 -243.599208)
		(width 0.088646)
		(layer "In2.Cu")
		(net "M_B_CPU0_SB_CB<7>")
	)
	(arc
		(start 338.43468 -243.108988)
		(mid 338.167649 -243.343896)
		(end 337.872832 -243.54282)
		(width 0.088646)
		(layer "In2.Cu")
		(net "M_B_CPU0_SB_CB<7>")
	)
	(arc
		(start 333.06385 -243.607082)
		(mid 332.787375 -243.674402)
		(end 332.513178 -243.598446)
		(width 0.088646)
		(layer "In2.Cu")
		(net "M_B_CPU0_SB_CB<7>")
	)
	(arc
		(start 332.513178 -243.598446)
		(mid 332.32598 -243.548303)
		(end 332.138782 -243.598446)
		(width 0.088646)
		(layer "In2.Cu")
		(net "M_B_CPU0_SB_CB<7>")
	)
	(arc
		(start 335.332832 -243.598446)
		(mid 335.145634 -243.548303)
		(end 334.958436 -243.598446)
		(width 0.088646)
		(layer "In2.Cu")
		(net "M_B_CPU0_SB_CB<7>")
	)
	(arc
		(start 335.898236 -243.598446)
		(mid 335.615534 -243.674222)
		(end 335.332832 -243.598446)
		(width 0.088646)
		(layer "In2.Cu")
		(net "M_B_CPU0_SB_CB<7>")
	)
	(segment
		(start 337.96478 -244.458744)
		(end 337.965034 -244.45849)
		(width 0.20066)
		(layer "F.Cu")
		(net "M_B_CPU0_SB_CB<6>")
	)
	(segment
		(start 295.777158 -240.711228)
		(end 295.777158 -240.3856)
		(width 0.20066)
		(layer "F.Cu")
		(net "M_B_CPU0_SB_CB<6>")
	)
	(segment
		(start 292.940486 -240.241836)
		(end 292.68547 -240.241836)
		(width 0.101854)
		(layer "F.Cu")
		(net "M_B_CPU0_SB_CB<6>")
	)
	(segment
		(start 296.373042 -240.878614)
		(end 295.944544 -240.878614)
		(width 0.20066)
		(layer "F.Cu")
		(net "M_B_CPU0_SB_CB<6>")
	)
	(segment
		(start 292.67531 -240.231676)
		(end 291.937948 -240.231676)
		(width 0.20066)
		(layer "F.Cu")
		(net "M_B_CPU0_SB_CB<6>")
	)
	(segment
		(start 291.937948 -240.231676)
		(end 291.502846 -240.666778)
		(width 0.20066)
		(layer "F.Cu")
		(net "M_B_CPU0_SB_CB<6>")
	)
	(segment
		(start 295.944544 -240.878614)
		(end 295.777158 -240.711228)
		(width 0.20066)
		(layer "F.Cu")
		(net "M_B_CPU0_SB_CB<6>")
	)
	(segment
		(start 295.633394 -240.241836)
		(end 295.000426 -240.241836)
		(width 0.20066)
		(layer "F.Cu")
		(net "M_B_CPU0_SB_CB<6>")
	)
	(segment
		(start 299.004482 -240.666778)
		(end 297.899582 -240.666778)
		(width 0.20066)
		(layer "F.Cu")
		(net "M_B_CPU0_SB_CB<6>")
	)
	(segment
		(start 297.899582 -240.666778)
		(end 296.584878 -240.666778)
		(width 0.20066)
		(layer "F.Cu")
		(net "M_B_CPU0_SB_CB<6>")
	)
	(segment
		(start 291.502846 -240.666778)
		(end 290.355782 -240.666778)
		(width 0.20066)
		(layer "F.Cu")
		(net "M_B_CPU0_SB_CB<6>")
	)
	(segment
		(start 292.68547 -240.241836)
		(end 292.67531 -240.231676)
		(width 0.101854)
		(layer "F.Cu")
		(net "M_B_CPU0_SB_CB<6>")
	)
	(segment
		(start 296.584878 -240.666778)
		(end 296.373042 -240.878614)
		(width 0.20066)
		(layer "F.Cu")
		(net "M_B_CPU0_SB_CB<6>")
	)
	(segment
		(start 337.965034 -244.45849)
		(end 337.965034 -243.922804)
		(width 0.20066)
		(layer "F.Cu")
		(net "M_B_CPU0_SB_CB<6>")
	)
	(segment
		(start 295.000426 -240.241836)
		(end 292.940486 -240.241836)
		(width 0.1016)
		(layer "F.Cu")
		(net "M_B_CPU0_SB_CB<6>")
	)
	(segment
		(start 295.777158 -240.3856)
		(end 295.633394 -240.241836)
		(width 0.20066)
		(layer "F.Cu")
		(net "M_B_CPU0_SB_CB<6>")
	)
	(segment
		(start 300.956472 -241.05489)
		(end 300.796452 -240.89487)
		(width 0.18288)
		(layer "In2.Cu")
		(net "M_B_CPU0_SB_CB<6>")
	)
	(segment
		(start 301.638208 -240.89487)
		(end 301.478188 -241.05489)
		(width 0.18288)
		(layer "In2.Cu")
		(net "M_B_CPU0_SB_CB<6>")
	)
	(segment
		(start 316.281816 -241.233198)
		(end 314.89904 -241.233198)
		(width 0.18288)
		(layer "In2.Cu")
		(net "M_B_CPU0_SB_CB<6>")
	)
	(segment
		(start 299.595032 -240.666778)
		(end 299.004482 -240.666778)
		(width 0.18288)
		(layer "In2.Cu")
		(net "M_B_CPU0_SB_CB<6>")
	)
	(segment
		(start 337.406488 -244.35435)
		(end 337.29295 -244.420898)
		(width 0.088646)
		(layer "In2.Cu")
		(net "M_B_CPU0_SB_CB<6>")
	)
	(segment
		(start 302.947578 -240.232946)
		(end 301.798228 -240.232946)
		(width 0.18288)
		(layer "In2.Cu")
		(net "M_B_CPU0_SB_CB<6>")
	)
	(segment
		(start 303.367694 -240.969038)
		(end 303.174654 -240.775998)
		(width 0.18288)
		(layer "In2.Cu")
		(net "M_B_CPU0_SB_CB<6>")
	)
	(segment
		(start 321.064128 -244.228366)
		(end 319.4812 -242.645438)
		(width 0.18288)
		(layer "In2.Cu")
		(net "M_B_CPU0_SB_CB<6>")
	)
	(segment
		(start 309.62473 -242.023392)
		(end 308.185312 -242.023392)
		(width 0.18288)
		(layer "In2.Cu")
		(net "M_B_CPU0_SB_CB<6>")
	)
	(segment
		(start 301.478188 -241.05489)
		(end 300.956472 -241.05489)
		(width 0.18288)
		(layer "In2.Cu")
		(net "M_B_CPU0_SB_CB<6>")
	)
	(segment
		(start 306.817268 -241.079528)
		(end 306.344828 -241.079528)
		(width 0.18288)
		(layer "In2.Cu")
		(net "M_B_CPU0_SB_CB<6>")
	)
	(segment
		(start 336.367882 -244.412262)
		(end 336.35315 -244.420898)
		(width 0.088646)
		(layer "In2.Cu")
		(net "M_B_CPU0_SB_CB<6>")
	)
	(segment
		(start 334.488282 -244.412262)
		(end 334.47355 -244.420898)
		(width 0.088646)
		(layer "In2.Cu")
		(net "M_B_CPU0_SB_CB<6>")
	)
	(segment
		(start 313.031124 -241.075972)
		(end 311.696862 -241.075972)
		(width 0.18288)
		(layer "In2.Cu")
		(net "M_B_CPU0_SB_CB<6>")
	)
	(segment
		(start 308.185312 -242.023392)
		(end 307.864764 -241.702844)
		(width 0.18288)
		(layer "In2.Cu")
		(net "M_B_CPU0_SB_CB<6>")
	)
	(segment
		(start 314.89904 -241.233198)
		(end 314.706 -241.426238)
		(width 0.18288)
		(layer "In2.Cu")
		(net "M_B_CPU0_SB_CB<6>")
	)
	(segment
		(start 332.608682 -244.412262)
		(end 332.59395 -244.420898)
		(width 0.088646)
		(layer "In2.Cu")
		(net "M_B_CPU0_SB_CB<6>")
	)
	(segment
		(start 301.638208 -240.392966)
		(end 301.638208 -240.89487)
		(width 0.18288)
		(layer "In2.Cu")
		(net "M_B_CPU0_SB_CB<6>")
	)
	(segment
		(start 315.41212 -242.452398)
		(end 315.41212 -242.132358)
		(width 0.18288)
		(layer "In2.Cu")
		(net "M_B_CPU0_SB_CB<6>")
	)
	(segment
		(start 310.793384 -241.97945)
		(end 310.502046 -241.97945)
		(width 0.18288)
		(layer "In2.Cu")
		(net "M_B_CPU0_SB_CB<6>")
	)
	(segment
		(start 303.174654 -240.775998)
		(end 303.174654 -240.460022)
		(width 0.18288)
		(layer "In2.Cu")
		(net "M_B_CPU0_SB_CB<6>")
	)
	(segment
		(start 300.074838 -240.186972)
		(end 299.595032 -240.666778)
		(width 0.18288)
		(layer "In2.Cu")
		(net "M_B_CPU0_SB_CB<6>")
	)
	(segment
		(start 306.195984 -241.228372)
		(end 304.67808 -241.228372)
		(width 0.18288)
		(layer "In2.Cu")
		(net "M_B_CPU0_SB_CB<6>")
	)
	(segment
		(start 300.629828 -240.186972)
		(end 300.074838 -240.186972)
		(width 0.18288)
		(layer "In2.Cu")
		(net "M_B_CPU0_SB_CB<6>")
	)
	(segment
		(start 331.004164 -244.228366)
		(end 321.064128 -244.228366)
		(width 0.18288)
		(layer "In2.Cu")
		(net "M_B_CPU0_SB_CB<6>")
	)
	(segment
		(start 310.222646 -241.70005)
		(end 309.948072 -241.70005)
		(width 0.18288)
		(layer "In2.Cu")
		(net "M_B_CPU0_SB_CB<6>")
	)
	(segment
		(start 331.399388 -244.228366)
		(end 331.004164 -244.228366)
		(width 0.088646)
		(layer "In2.Cu")
		(net "M_B_CPU0_SB_CB<6>")
	)
	(segment
		(start 311.696862 -241.075972)
		(end 310.793384 -241.97945)
		(width 0.18288)
		(layer "In2.Cu")
		(net "M_B_CPU0_SB_CB<6>")
	)
	(segment
		(start 309.948072 -241.70005)
		(end 309.62473 -242.023392)
		(width 0.18288)
		(layer "In2.Cu")
		(net "M_B_CPU0_SB_CB<6>")
	)
	(segment
		(start 304.418746 -240.969038)
		(end 303.367694 -240.969038)
		(width 0.18288)
		(layer "In2.Cu")
		(net "M_B_CPU0_SB_CB<6>")
	)
	(segment
		(start 304.67808 -241.228372)
		(end 304.418746 -240.969038)
		(width 0.18288)
		(layer "In2.Cu")
		(net "M_B_CPU0_SB_CB<6>")
	)
	(segment
		(start 306.344828 -241.079528)
		(end 306.195984 -241.228372)
		(width 0.18288)
		(layer "In2.Cu")
		(net "M_B_CPU0_SB_CB<6>")
	)
	(segment
		(start 307.864764 -241.702844)
		(end 307.440584 -241.702844)
		(width 0.18288)
		(layer "In2.Cu")
		(net "M_B_CPU0_SB_CB<6>")
	)
	(segment
		(start 316.474856 -241.746278)
		(end 316.474856 -241.426238)
		(width 0.18288)
		(layer "In2.Cu")
		(net "M_B_CPU0_SB_CB<6>")
	)
	(segment
		(start 333.548482 -244.412262)
		(end 333.53375 -244.420898)
		(width 0.088646)
		(layer "In2.Cu")
		(net "M_B_CPU0_SB_CB<6>")
	)
	(segment
		(start 300.796452 -240.89487)
		(end 300.796452 -240.353596)
		(width 0.18288)
		(layer "In2.Cu")
		(net "M_B_CPU0_SB_CB<6>")
	)
	(segment
		(start 315.60516 -242.645438)
		(end 315.41212 -242.452398)
		(width 0.18288)
		(layer "In2.Cu")
		(net "M_B_CPU0_SB_CB<6>")
	)
	(segment
		(start 319.4812 -242.645438)
		(end 315.60516 -242.645438)
		(width 0.18288)
		(layer "In2.Cu")
		(net "M_B_CPU0_SB_CB<6>")
	)
	(segment
		(start 331.521308 -244.350286)
		(end 331.399388 -244.228366)
		(width 0.088646)
		(layer "In2.Cu")
		(net "M_B_CPU0_SB_CB<6>")
	)
	(segment
		(start 315.60516 -241.939318)
		(end 316.281816 -241.939318)
		(width 0.18288)
		(layer "In2.Cu")
		(net "M_B_CPU0_SB_CB<6>")
	)
	(segment
		(start 303.174654 -240.460022)
		(end 302.947578 -240.232946)
		(width 0.18288)
		(layer "In2.Cu")
		(net "M_B_CPU0_SB_CB<6>")
	)
	(segment
		(start 313.940698 -242.452398)
		(end 313.940698 -241.985546)
		(width 0.18288)
		(layer "In2.Cu")
		(net "M_B_CPU0_SB_CB<6>")
	)
	(segment
		(start 307.440584 -241.702844)
		(end 306.817268 -241.079528)
		(width 0.18288)
		(layer "In2.Cu")
		(net "M_B_CPU0_SB_CB<6>")
	)
	(segment
		(start 331.811884 -244.350286)
		(end 331.521308 -244.350286)
		(width 0.088646)
		(layer "In2.Cu")
		(net "M_B_CPU0_SB_CB<6>")
	)
	(segment
		(start 314.706 -242.452398)
		(end 314.51296 -242.645438)
		(width 0.18288)
		(layer "In2.Cu")
		(net "M_B_CPU0_SB_CB<6>")
	)
	(segment
		(start 310.502046 -241.97945)
		(end 310.222646 -241.70005)
		(width 0.18288)
		(layer "In2.Cu")
		(net "M_B_CPU0_SB_CB<6>")
	)
	(segment
		(start 314.133738 -242.645438)
		(end 313.940698 -242.452398)
		(width 0.18288)
		(layer "In2.Cu")
		(net "M_B_CPU0_SB_CB<6>")
	)
	(segment
		(start 316.474856 -241.426238)
		(end 316.281816 -241.233198)
		(width 0.18288)
		(layer "In2.Cu")
		(net "M_B_CPU0_SB_CB<6>")
	)
	(segment
		(start 300.796452 -240.353596)
		(end 300.629828 -240.186972)
		(width 0.18288)
		(layer "In2.Cu")
		(net "M_B_CPU0_SB_CB<6>")
	)
	(segment
		(start 313.940698 -241.985546)
		(end 313.031124 -241.075972)
		(width 0.18288)
		(layer "In2.Cu")
		(net "M_B_CPU0_SB_CB<6>")
	)
	(segment
		(start 301.798228 -240.232946)
		(end 301.638208 -240.392966)
		(width 0.18288)
		(layer "In2.Cu")
		(net "M_B_CPU0_SB_CB<6>")
	)
	(segment
		(start 314.706 -241.426238)
		(end 314.706 -242.452398)
		(width 0.18288)
		(layer "In2.Cu")
		(net "M_B_CPU0_SB_CB<6>")
	)
	(segment
		(start 335.428082 -244.412262)
		(end 335.41335 -244.420898)
		(width 0.088646)
		(layer "In2.Cu")
		(net "M_B_CPU0_SB_CB<6>")
	)
	(segment
		(start 314.51296 -242.645438)
		(end 314.133738 -242.645438)
		(width 0.18288)
		(layer "In2.Cu")
		(net "M_B_CPU0_SB_CB<6>")
	)
	(segment
		(start 316.281816 -241.939318)
		(end 316.474856 -241.746278)
		(width 0.18288)
		(layer "In2.Cu")
		(net "M_B_CPU0_SB_CB<6>")
	)
	(segment
		(start 315.41212 -242.132358)
		(end 315.60516 -241.939318)
		(width 0.18288)
		(layer "In2.Cu")
		(net "M_B_CPU0_SB_CB<6>")
	)
	(arc
		(start 333.922878 -244.412262)
		(mid 333.73568 -244.362119)
		(end 333.548482 -244.412262)
		(width 0.088646)
		(layer "In2.Cu")
		(net "M_B_CPU0_SB_CB<6>")
	)
	(arc
		(start 334.862678 -244.412262)
		(mid 334.67548 -244.362119)
		(end 334.488282 -244.412262)
		(width 0.088646)
		(layer "In2.Cu")
		(net "M_B_CPU0_SB_CB<6>")
	)
	(arc
		(start 335.802478 -244.412262)
		(mid 335.61528 -244.362119)
		(end 335.428082 -244.412262)
		(width 0.088646)
		(layer "In2.Cu")
		(net "M_B_CPU0_SB_CB<6>")
	)
	(arc
		(start 337.29295 -244.420898)
		(mid 337.016475 -244.488218)
		(end 336.742278 -244.412262)
		(width 0.088646)
		(layer "In2.Cu")
		(net "M_B_CPU0_SB_CB<6>")
	)
	(arc
		(start 335.41335 -244.420898)
		(mid 335.136875 -244.488218)
		(end 334.862678 -244.412262)
		(width 0.088646)
		(layer "In2.Cu")
		(net "M_B_CPU0_SB_CB<6>")
	)
	(arc
		(start 332.983078 -244.412262)
		(mid 332.79588 -244.362119)
		(end 332.608682 -244.412262)
		(width 0.088646)
		(layer "In2.Cu")
		(net "M_B_CPU0_SB_CB<6>")
	)
	(arc
		(start 332.043278 -244.412262)
		(mid 331.931662 -244.366032)
		(end 331.811884 -244.350286)
		(width 0.088646)
		(layer "In2.Cu")
		(net "M_B_CPU0_SB_CB<6>")
	)
	(arc
		(start 333.53375 -244.420898)
		(mid 333.257275 -244.488218)
		(end 332.983078 -244.412262)
		(width 0.088646)
		(layer "In2.Cu")
		(net "M_B_CPU0_SB_CB<6>")
	)
	(arc
		(start 337.965034 -243.922804)
		(mid 337.699543 -244.156415)
		(end 337.406488 -244.35435)
		(width 0.088646)
		(layer "In2.Cu")
		(net "M_B_CPU0_SB_CB<6>")
	)
	(arc
		(start 336.742278 -244.412262)
		(mid 336.55508 -244.362119)
		(end 336.367882 -244.412262)
		(width 0.088646)
		(layer "In2.Cu")
		(net "M_B_CPU0_SB_CB<6>")
	)
	(arc
		(start 334.47355 -244.420898)
		(mid 334.197075 -244.488218)
		(end 333.922878 -244.412262)
		(width 0.088646)
		(layer "In2.Cu")
		(net "M_B_CPU0_SB_CB<6>")
	)
	(arc
		(start 336.35315 -244.420898)
		(mid 336.076675 -244.488218)
		(end 335.802478 -244.412262)
		(width 0.088646)
		(layer "In2.Cu")
		(net "M_B_CPU0_SB_CB<6>")
	)
	(arc
		(start 332.59395 -244.420898)
		(mid 332.317475 -244.488218)
		(end 332.043278 -244.412262)
		(width 0.088646)
		(layer "In2.Cu")
		(net "M_B_CPU0_SB_CB<6>")
	)
	(segment
		(start 292.160198 -239.81664)
		(end 291.735256 -239.391698)
		(width 0.20066)
		(layer "F.Cu")
		(net "M_B_CPU0_SB_CB<5>")
	)
	(segment
		(start 289.240468 -239.391698)
		(end 289.231578 -239.382808)
		(width 0.1016)
		(layer "F.Cu")
		(net "M_B_CPU0_SB_CB<5>")
	)
	(segment
		(start 293.799514 -239.81664)
		(end 292.160198 -239.81664)
		(width 0.20066)
		(layer "F.Cu")
		(net "M_B_CPU0_SB_CB<5>")
	)
	(segment
		(start 294.904414 -239.81664)
		(end 293.799514 -239.81664)
		(width 0.20066)
		(layer "F.Cu")
		(net "M_B_CPU0_SB_CB<5>")
	)
	(segment
		(start 289.231578 -239.382808)
		(end 288.62274 -239.382808)
		(width 0.20066)
		(layer "F.Cu")
		(net "M_B_CPU0_SB_CB<5>")
	)
	(segment
		(start 288.46018 -239.545368)
		(end 288.46018 -239.873536)
		(width 0.20066)
		(layer "F.Cu")
		(net "M_B_CPU0_SB_CB<5>")
	)
	(segment
		(start 288.62274 -239.382808)
		(end 288.46018 -239.545368)
		(width 0.20066)
		(layer "F.Cu")
		(net "M_B_CPU0_SB_CB<5>")
	)
	(segment
		(start 288.46018 -239.873536)
		(end 288.305748 -240.027968)
		(width 0.20066)
		(layer "F.Cu")
		(net "M_B_CPU0_SB_CB<5>")
	)
	(segment
		(start 336.555334 -243.644928)
		(end 336.55508 -243.644674)
		(width 0.20066)
		(layer "F.Cu")
		(net "M_B_CPU0_SB_CB<5>")
	)
	(segment
		(start 291.225986 -239.391698)
		(end 289.240468 -239.391698)
		(width 0.1016)
		(layer "F.Cu")
		(net "M_B_CPU0_SB_CB<5>")
	)
	(segment
		(start 291.735256 -239.391698)
		(end 291.556694 -239.391698)
		(width 0.20066)
		(layer "F.Cu")
		(net "M_B_CPU0_SB_CB<5>")
	)
	(segment
		(start 288.305748 -240.027968)
		(end 287.801304 -240.027968)
		(width 0.20066)
		(layer "F.Cu")
		(net "M_B_CPU0_SB_CB<5>")
	)
	(segment
		(start 336.55508 -243.644674)
		(end 336.55508 -243.108988)
		(width 0.20066)
		(layer "F.Cu")
		(net "M_B_CPU0_SB_CB<5>")
	)
	(segment
		(start 291.556694 -239.391698)
		(end 291.225986 -239.391698)
		(width 0.101854)
		(layer "F.Cu")
		(net "M_B_CPU0_SB_CB<5>")
	)
	(segment
		(start 287.801304 -240.027968)
		(end 287.589976 -239.81664)
		(width 0.20066)
		(layer "F.Cu")
		(net "M_B_CPU0_SB_CB<5>")
	)
	(segment
		(start 287.589976 -239.81664)
		(end 286.255714 -239.81664)
		(width 0.20066)
		(layer "F.Cu")
		(net "M_B_CPU0_SB_CB<5>")
	)
	(segment
		(start 331.667612 -243.48567)
		(end 331.373988 -243.192046)
		(width 0.088646)
		(layer "In2.Cu")
		(net "M_B_CPU0_SB_CB<5>")
	)
	(segment
		(start 295.633902 -238.801656)
		(end 296.065448 -239.233202)
		(width 0.18288)
		(layer "In2.Cu")
		(net "M_B_CPU0_SB_CB<5>")
	)
	(segment
		(start 298.213526 -237.922562)
		(end 298.020486 -237.729522)
		(width 0.18288)
		(layer "In2.Cu")
		(net "M_B_CPU0_SB_CB<5>")
	)
	(segment
		(start 295.754806 -239.81664)
		(end 294.904414 -239.81664)
		(width 0.18288)
		(layer "In2.Cu")
		(net "M_B_CPU0_SB_CB<5>")
	)
	(segment
		(start 322.222622 -243.192046)
		(end 319.235328 -240.204752)
		(width 0.18288)
		(layer "In2.Cu")
		(net "M_B_CPU0_SB_CB<5>")
	)
	(segment
		(start 295.633902 -238.52886)
		(end 295.633902 -238.801656)
		(width 0.18288)
		(layer "In2.Cu")
		(net "M_B_CPU0_SB_CB<5>")
	)
	(segment
		(start 297.265344 -237.922562)
		(end 297.265344 -238.34217)
		(width 0.18288)
		(layer "In2.Cu")
		(net "M_B_CPU0_SB_CB<5>")
	)
	(segment
		(start 299.195998 -238.541814)
		(end 298.406566 -238.541814)
		(width 0.18288)
		(layer "In2.Cu")
		(net "M_B_CPU0_SB_CB<5>")
	)
	(segment
		(start 298.020486 -237.729522)
		(end 297.458384 -237.729522)
		(width 0.18288)
		(layer "In2.Cu")
		(net "M_B_CPU0_SB_CB<5>")
	)
	(segment
		(start 295.86047 -238.302292)
		(end 295.633902 -238.52886)
		(width 0.18288)
		(layer "In2.Cu")
		(net "M_B_CPU0_SB_CB<5>")
	)
	(segment
		(start 297.458384 -237.729522)
		(end 297.265344 -237.922562)
		(width 0.18288)
		(layer "In2.Cu")
		(net "M_B_CPU0_SB_CB<5>")
	)
	(segment
		(start 310.365394 -239.419638)
		(end 307.424836 -239.419638)
		(width 0.18288)
		(layer "In2.Cu")
		(net "M_B_CPU0_SB_CB<5>")
	)
	(segment
		(start 300.005242 -237.73257)
		(end 299.195998 -238.541814)
		(width 0.18288)
		(layer "In2.Cu")
		(net "M_B_CPU0_SB_CB<5>")
	)
	(segment
		(start 310.686704 -239.098328)
		(end 310.365394 -239.419638)
		(width 0.18288)
		(layer "In2.Cu")
		(net "M_B_CPU0_SB_CB<5>")
	)
	(segment
		(start 296.564812 -238.733838)
		(end 296.133266 -238.302292)
		(width 0.18288)
		(layer "In2.Cu")
		(net "M_B_CPU0_SB_CB<5>")
	)
	(segment
		(start 306.573428 -238.56823)
		(end 303.935892 -238.56823)
		(width 0.18288)
		(layer "In2.Cu")
		(net "M_B_CPU0_SB_CB<5>")
	)
	(segment
		(start 331.848206 -243.48567)
		(end 331.667612 -243.48567)
		(width 0.088646)
		(layer "In2.Cu")
		(net "M_B_CPU0_SB_CB<5>")
	)
	(segment
		(start 296.873676 -238.733838)
		(end 296.564812 -238.733838)
		(width 0.18288)
		(layer "In2.Cu")
		(net "M_B_CPU0_SB_CB<5>")
	)
	(segment
		(start 319.235328 -240.204752)
		(end 315.328554 -238.586518)
		(width 0.18288)
		(layer "In2.Cu")
		(net "M_B_CPU0_SB_CB<5>")
	)
	(segment
		(start 297.265344 -238.34217)
		(end 296.873676 -238.733838)
		(width 0.18288)
		(layer "In2.Cu")
		(net "M_B_CPU0_SB_CB<5>")
	)
	(segment
		(start 307.424836 -239.419638)
		(end 306.573428 -238.56823)
		(width 0.18288)
		(layer "In2.Cu")
		(net "M_B_CPU0_SB_CB<5>")
	)
	(segment
		(start 332.058264 -243.42471)
		(end 332.043532 -243.433346)
		(width 0.088646)
		(layer "In2.Cu")
		(net "M_B_CPU0_SB_CB<5>")
	)
	(segment
		(start 298.213526 -238.348774)
		(end 298.213526 -237.922562)
		(width 0.18288)
		(layer "In2.Cu")
		(net "M_B_CPU0_SB_CB<5>")
	)
	(segment
		(start 315.328554 -238.586518)
		(end 313.54014 -238.586518)
		(width 0.18288)
		(layer "In2.Cu")
		(net "M_B_CPU0_SB_CB<5>")
	)
	(segment
		(start 298.406566 -238.541814)
		(end 298.213526 -238.348774)
		(width 0.18288)
		(layer "In2.Cu")
		(net "M_B_CPU0_SB_CB<5>")
	)
	(segment
		(start 296.065448 -239.233202)
		(end 296.065448 -239.505998)
		(width 0.18288)
		(layer "In2.Cu")
		(net "M_B_CPU0_SB_CB<5>")
	)
	(segment
		(start 296.065448 -239.505998)
		(end 295.754806 -239.81664)
		(width 0.18288)
		(layer "In2.Cu")
		(net "M_B_CPU0_SB_CB<5>")
	)
	(segment
		(start 296.133266 -238.302292)
		(end 295.86047 -238.302292)
		(width 0.18288)
		(layer "In2.Cu")
		(net "M_B_CPU0_SB_CB<5>")
	)
	(segment
		(start 331.004164 -243.192046)
		(end 322.222622 -243.192046)
		(width 0.18288)
		(layer "In2.Cu")
		(net "M_B_CPU0_SB_CB<5>")
	)
	(segment
		(start 332.998064 -243.42471)
		(end 332.983332 -243.433346)
		(width 0.088646)
		(layer "In2.Cu")
		(net "M_B_CPU0_SB_CB<5>")
	)
	(segment
		(start 331.373988 -243.192046)
		(end 331.004164 -243.192046)
		(width 0.088646)
		(layer "In2.Cu")
		(net "M_B_CPU0_SB_CB<5>")
	)
	(segment
		(start 313.54014 -238.586518)
		(end 313.539886 -238.586772)
		(width 0.18288)
		(layer "In2.Cu")
		(net "M_B_CPU0_SB_CB<5>")
	)
	(segment
		(start 335.830672 -243.41709)
		(end 335.802732 -243.433346)
		(width 0.088646)
		(layer "In2.Cu")
		(net "M_B_CPU0_SB_CB<5>")
	)
	(segment
		(start 303.100232 -237.73257)
		(end 300.005242 -237.73257)
		(width 0.18288)
		(layer "In2.Cu")
		(net "M_B_CPU0_SB_CB<5>")
	)
	(segment
		(start 303.935892 -238.56823)
		(end 303.100232 -237.73257)
		(width 0.18288)
		(layer "In2.Cu")
		(net "M_B_CPU0_SB_CB<5>")
	)
	(segment
		(start 310.879744 -238.586772)
		(end 310.686704 -238.779812)
		(width 0.18288)
		(layer "In2.Cu")
		(net "M_B_CPU0_SB_CB<5>")
	)
	(segment
		(start 310.686704 -238.779812)
		(end 310.686704 -239.098328)
		(width 0.18288)
		(layer "In2.Cu")
		(net "M_B_CPU0_SB_CB<5>")
	)
	(segment
		(start 336.55508 -243.108988)
		(end 335.830672 -243.41709)
		(width 0.088646)
		(layer "In2.Cu")
		(net "M_B_CPU0_SB_CB<5>")
	)
	(segment
		(start 313.539886 -238.586772)
		(end 310.879744 -238.586772)
		(width 0.18288)
		(layer "In2.Cu")
		(net "M_B_CPU0_SB_CB<5>")
	)
	(arc
		(start 335.428336 -243.433346)
		(mid 335.145634 -243.35757)
		(end 334.862932 -243.433346)
		(width 0.088646)
		(layer "In2.Cu")
		(net "M_B_CPU0_SB_CB<5>")
	)
	(arc
		(start 334.488536 -243.433346)
		(mid 334.205834 -243.35757)
		(end 333.923132 -243.433346)
		(width 0.088646)
		(layer "In2.Cu")
		(net "M_B_CPU0_SB_CB<5>")
	)
	(arc
		(start 332.983332 -243.433346)
		(mid 332.796134 -243.483489)
		(end 332.608936 -243.433346)
		(width 0.088646)
		(layer "In2.Cu")
		(net "M_B_CPU0_SB_CB<5>")
	)
	(arc
		(start 334.862932 -243.433346)
		(mid 334.675734 -243.483489)
		(end 334.488536 -243.433346)
		(width 0.088646)
		(layer "In2.Cu")
		(net "M_B_CPU0_SB_CB<5>")
	)
	(arc
		(start 333.548736 -243.433346)
		(mid 333.274537 -243.357511)
		(end 332.998064 -243.42471)
		(width 0.088646)
		(layer "In2.Cu")
		(net "M_B_CPU0_SB_CB<5>")
	)
	(arc
		(start 332.043532 -243.433346)
		(mid 331.94931 -243.472346)
		(end 331.848206 -243.48567)
		(width 0.088646)
		(layer "In2.Cu")
		(net "M_B_CPU0_SB_CB<5>")
	)
	(arc
		(start 335.802732 -243.433346)
		(mid 335.615534 -243.483489)
		(end 335.428336 -243.433346)
		(width 0.088646)
		(layer "In2.Cu")
		(net "M_B_CPU0_SB_CB<5>")
	)
	(arc
		(start 332.608936 -243.433346)
		(mid 332.334737 -243.357511)
		(end 332.058264 -243.42471)
		(width 0.088646)
		(layer "In2.Cu")
		(net "M_B_CPU0_SB_CB<5>")
	)
	(arc
		(start 333.923132 -243.433346)
		(mid 333.735934 -243.483489)
		(end 333.548736 -243.433346)
		(width 0.088646)
		(layer "In2.Cu")
		(net "M_B_CPU0_SB_CB<5>")
	)
	(segment
		(start 288.46018 -241.293142)
		(end 288.46018 -241.582702)
		(width 0.20066)
		(layer "F.Cu")
		(net "M_B_CPU0_SB_CB<4>")
	)
	(segment
		(start 289.48761 -241.09172)
		(end 289.239706 -241.09172)
		(width 0.101854)
		(layer "F.Cu")
		(net "M_B_CPU0_SB_CB<4>")
	)
	(segment
		(start 289.231578 -241.083592)
		(end 288.66973 -241.083592)
		(width 0.20066)
		(layer "F.Cu")
		(net "M_B_CPU0_SB_CB<4>")
	)
	(segment
		(start 288.28746 -241.755422)
		(end 287.828736 -241.755422)
		(width 0.20066)
		(layer "F.Cu")
		(net "M_B_CPU0_SB_CB<4>")
	)
	(segment
		(start 287.589976 -241.516662)
		(end 286.255714 -241.516662)
		(width 0.20066)
		(layer "F.Cu")
		(net "M_B_CPU0_SB_CB<4>")
	)
	(segment
		(start 292.430454 -241.516662)
		(end 292.005512 -241.09172)
		(width 0.20066)
		(layer "F.Cu")
		(net "M_B_CPU0_SB_CB<4>")
	)
	(segment
		(start 289.239706 -241.09172)
		(end 289.231578 -241.083592)
		(width 0.101854)
		(layer "F.Cu")
		(net "M_B_CPU0_SB_CB<4>")
	)
	(segment
		(start 292.005512 -241.09172)
		(end 291.556694 -241.09172)
		(width 0.20066)
		(layer "F.Cu")
		(net "M_B_CPU0_SB_CB<4>")
	)
	(segment
		(start 337.02498 -244.458744)
		(end 337.025234 -244.45849)
		(width 0.20066)
		(layer "F.Cu")
		(net "M_B_CPU0_SB_CB<4>")
	)
	(segment
		(start 337.025234 -244.45849)
		(end 337.025234 -243.922804)
		(width 0.20066)
		(layer "F.Cu")
		(net "M_B_CPU0_SB_CB<4>")
	)
	(segment
		(start 288.66973 -241.083592)
		(end 288.46018 -241.293142)
		(width 0.20066)
		(layer "F.Cu")
		(net "M_B_CPU0_SB_CB<4>")
	)
	(segment
		(start 288.46018 -241.582702)
		(end 288.28746 -241.755422)
		(width 0.20066)
		(layer "F.Cu")
		(net "M_B_CPU0_SB_CB<4>")
	)
	(segment
		(start 294.904414 -241.516662)
		(end 293.799514 -241.516662)
		(width 0.20066)
		(layer "F.Cu")
		(net "M_B_CPU0_SB_CB<4>")
	)
	(segment
		(start 287.828736 -241.755422)
		(end 287.589976 -241.516662)
		(width 0.20066)
		(layer "F.Cu")
		(net "M_B_CPU0_SB_CB<4>")
	)
	(segment
		(start 291.556694 -241.09172)
		(end 289.48761 -241.09172)
		(width 0.1016)
		(layer "F.Cu")
		(net "M_B_CPU0_SB_CB<4>")
	)
	(segment
		(start 293.799514 -241.516662)
		(end 292.430454 -241.516662)
		(width 0.20066)
		(layer "F.Cu")
		(net "M_B_CPU0_SB_CB<4>")
	)
	(segment
		(start 304.668428 -240.156492)
		(end 304.54981 -240.27511)
		(width 0.18288)
		(layer "In2.Cu")
		(net "M_B_CPU0_SB_CB<4>")
	)
	(segment
		(start 331.333348 -243.882926)
		(end 331.004164 -243.882926)
		(width 0.088646)
		(layer "In2.Cu")
		(net "M_B_CPU0_SB_CB<4>")
	)
	(segment
		(start 317.005208 -241.938302)
		(end 317.005208 -240.899696)
		(width 0.18288)
		(layer "In2.Cu")
		(net "M_B_CPU0_SB_CB<4>")
	)
	(segment
		(start 333.467964 -244.238526)
		(end 333.453232 -244.247162)
		(width 0.088646)
		(layer "In2.Cu")
		(net "M_B_CPU0_SB_CB<4>")
	)
	(segment
		(start 337.025234 -243.922804)
		(end 336.642456 -244.073934)
		(width 0.088646)
		(layer "In2.Cu")
		(net "M_B_CPU0_SB_CB<4>")
	)
	(segment
		(start 295.803066 -241.175286)
		(end 296.00017 -241.37239)
		(width 0.18288)
		(layer "In2.Cu")
		(net "M_B_CPU0_SB_CB<4>")
	)
	(segment
		(start 307.031644 -240.542572)
		(end 306.529994 -240.542572)
		(width 0.18288)
		(layer "In2.Cu")
		(net "M_B_CPU0_SB_CB<4>")
	)
	(segment
		(start 302.13935 -239.323372)
		(end 300.53915 -239.323372)
		(width 0.18288)
		(layer "In2.Cu")
		(net "M_B_CPU0_SB_CB<4>")
	)
	(segment
		(start 321.460114 -243.882926)
		(end 319.70853 -242.131342)
		(width 0.18288)
		(layer "In2.Cu")
		(net "M_B_CPU0_SB_CB<4>")
	)
	(segment
		(start 317.198248 -242.131342)
		(end 317.005208 -241.938302)
		(width 0.18288)
		(layer "In2.Cu")
		(net "M_B_CPU0_SB_CB<4>")
	)
	(segment
		(start 308.037484 -241.138964)
		(end 307.628036 -241.138964)
		(width 0.18288)
		(layer "In2.Cu")
		(net "M_B_CPU0_SB_CB<4>")
	)
	(segment
		(start 332.528164 -244.238526)
		(end 332.513432 -244.247162)
		(width 0.088646)
		(layer "In2.Cu")
		(net "M_B_CPU0_SB_CB<4>")
	)
	(segment
		(start 302.39335 -239.577372)
		(end 302.13935 -239.323372)
		(width 0.18288)
		(layer "In2.Cu")
		(net "M_B_CPU0_SB_CB<4>")
	)
	(segment
		(start 336.642456 -244.073934)
		(end 336.36712 -244.19179)
		(width 0.088646)
		(layer "In2.Cu")
		(net "M_B_CPU0_SB_CB<4>")
	)
	(segment
		(start 295.80713 -241.798094)
		(end 295.185846 -241.798094)
		(width 0.18288)
		(layer "In2.Cu")
		(net "M_B_CPU0_SB_CB<4>")
	)
	(segment
		(start 336.36712 -244.19179)
		(end 336.272632 -244.247162)
		(width 0.088646)
		(layer "In2.Cu")
		(net "M_B_CPU0_SB_CB<4>")
	)
	(segment
		(start 313.662568 -240.013236)
		(end 312.332878 -240.013236)
		(width 0.18288)
		(layer "In2.Cu")
		(net "M_B_CPU0_SB_CB<4>")
	)
	(segment
		(start 295.803066 -240.767616)
		(end 295.803066 -241.175286)
		(width 0.18288)
		(layer "In2.Cu")
		(net "M_B_CPU0_SB_CB<4>")
	)
	(segment
		(start 303.23155 -239.577372)
		(end 302.39335 -239.577372)
		(width 0.18288)
		(layer "In2.Cu")
		(net "M_B_CPU0_SB_CB<4>")
	)
	(segment
		(start 317.005208 -240.899696)
		(end 316.812168 -240.706656)
		(width 0.18288)
		(layer "In2.Cu")
		(net "M_B_CPU0_SB_CB<4>")
	)
	(segment
		(start 316.812168 -240.706656)
		(end 314.355988 -240.706656)
		(width 0.18288)
		(layer "In2.Cu")
		(net "M_B_CPU0_SB_CB<4>")
	)
	(segment
		(start 319.70853 -242.131342)
		(end 317.198248 -242.131342)
		(width 0.18288)
		(layer "In2.Cu")
		(net "M_B_CPU0_SB_CB<4>")
	)
	(segment
		(start 296.884852 -240.377472)
		(end 296.19321 -240.377472)
		(width 0.18288)
		(layer "In2.Cu")
		(net "M_B_CPU0_SB_CB<4>")
	)
	(segment
		(start 310.793638 -241.140742)
		(end 309.83555 -241.140742)
		(width 0.18288)
		(layer "In2.Cu")
		(net "M_B_CPU0_SB_CB<4>")
	)
	(segment
		(start 334.407764 -244.238526)
		(end 334.393032 -244.247162)
		(width 0.088646)
		(layer "In2.Cu")
		(net "M_B_CPU0_SB_CB<4>")
	)
	(segment
		(start 295.185846 -241.798094)
		(end 294.904414 -241.516662)
		(width 0.18288)
		(layer "In2.Cu")
		(net "M_B_CPU0_SB_CB<4>")
	)
	(segment
		(start 312.051446 -240.294668)
		(end 311.639712 -240.294668)
		(width 0.18288)
		(layer "In2.Cu")
		(net "M_B_CPU0_SB_CB<4>")
	)
	(segment
		(start 300.53915 -239.323372)
		(end 300.467522 -239.395)
		(width 0.18288)
		(layer "In2.Cu")
		(net "M_B_CPU0_SB_CB<4>")
	)
	(segment
		(start 312.332878 -240.013236)
		(end 312.051446 -240.294668)
		(width 0.18288)
		(layer "In2.Cu")
		(net "M_B_CPU0_SB_CB<4>")
	)
	(segment
		(start 309.83555 -241.140742)
		(end 309.61076 -240.915952)
		(width 0.18288)
		(layer "In2.Cu")
		(net "M_B_CPU0_SB_CB<4>")
	)
	(segment
		(start 306.143914 -240.156492)
		(end 304.668428 -240.156492)
		(width 0.18288)
		(layer "In2.Cu")
		(net "M_B_CPU0_SB_CB<4>")
	)
	(segment
		(start 296.00017 -241.37239)
		(end 296.00017 -241.605054)
		(width 0.18288)
		(layer "In2.Cu")
		(net "M_B_CPU0_SB_CB<4>")
	)
	(segment
		(start 297.57624 -239.395)
		(end 297.334178 -239.637062)
		(width 0.18288)
		(layer "In2.Cu")
		(net "M_B_CPU0_SB_CB<4>")
	)
	(segment
		(start 296.00017 -241.605054)
		(end 295.80713 -241.798094)
		(width 0.18288)
		(layer "In2.Cu")
		(net "M_B_CPU0_SB_CB<4>")
	)
	(segment
		(start 307.628036 -241.138964)
		(end 307.031644 -240.542572)
		(width 0.18288)
		(layer "In2.Cu")
		(net "M_B_CPU0_SB_CB<4>")
	)
	(segment
		(start 331.004164 -243.882926)
		(end 321.460114 -243.882926)
		(width 0.18288)
		(layer "In2.Cu")
		(net "M_B_CPU0_SB_CB<4>")
	)
	(segment
		(start 297.334178 -239.928146)
		(end 296.884852 -240.377472)
		(width 0.18288)
		(layer "In2.Cu")
		(net "M_B_CPU0_SB_CB<4>")
	)
	(segment
		(start 331.601064 -244.150642)
		(end 331.333348 -243.882926)
		(width 0.088646)
		(layer "In2.Cu")
		(net "M_B_CPU0_SB_CB<4>")
	)
	(segment
		(start 314.355988 -240.706656)
		(end 313.662568 -240.013236)
		(width 0.18288)
		(layer "In2.Cu")
		(net "M_B_CPU0_SB_CB<4>")
	)
	(segment
		(start 308.260496 -240.915952)
		(end 308.037484 -241.138964)
		(width 0.18288)
		(layer "In2.Cu")
		(net "M_B_CPU0_SB_CB<4>")
	)
	(segment
		(start 296.19321 -240.377472)
		(end 295.803066 -240.767616)
		(width 0.18288)
		(layer "In2.Cu")
		(net "M_B_CPU0_SB_CB<4>")
	)
	(segment
		(start 306.529994 -240.542572)
		(end 306.143914 -240.156492)
		(width 0.18288)
		(layer "In2.Cu")
		(net "M_B_CPU0_SB_CB<4>")
	)
	(segment
		(start 303.929288 -240.27511)
		(end 303.23155 -239.577372)
		(width 0.18288)
		(layer "In2.Cu")
		(net "M_B_CPU0_SB_CB<4>")
	)
	(segment
		(start 297.334178 -239.637062)
		(end 297.334178 -239.928146)
		(width 0.18288)
		(layer "In2.Cu")
		(net "M_B_CPU0_SB_CB<4>")
	)
	(segment
		(start 331.779372 -244.150642)
		(end 331.601064 -244.150642)
		(width 0.088646)
		(layer "In2.Cu")
		(net "M_B_CPU0_SB_CB<4>")
	)
	(segment
		(start 304.54981 -240.27511)
		(end 303.929288 -240.27511)
		(width 0.18288)
		(layer "In2.Cu")
		(net "M_B_CPU0_SB_CB<4>")
	)
	(segment
		(start 300.467522 -239.395)
		(end 297.57624 -239.395)
		(width 0.18288)
		(layer "In2.Cu")
		(net "M_B_CPU0_SB_CB<4>")
	)
	(segment
		(start 335.347564 -244.238526)
		(end 335.332832 -244.247162)
		(width 0.088646)
		(layer "In2.Cu")
		(net "M_B_CPU0_SB_CB<4>")
	)
	(segment
		(start 311.639712 -240.294668)
		(end 310.793638 -241.140742)
		(width 0.18288)
		(layer "In2.Cu")
		(net "M_B_CPU0_SB_CB<4>")
	)
	(segment
		(start 309.61076 -240.915952)
		(end 308.260496 -240.915952)
		(width 0.18288)
		(layer "In2.Cu")
		(net "M_B_CPU0_SB_CB<4>")
	)
	(arc
		(start 332.139036 -244.247162)
		(mid 331.965568 -244.175186)
		(end 331.779372 -244.150642)
		(width 0.088646)
		(layer "In2.Cu")
		(net "M_B_CPU0_SB_CB<4>")
	)
	(arc
		(start 335.332832 -244.247162)
		(mid 335.145634 -244.297305)
		(end 334.958436 -244.247162)
		(width 0.088646)
		(layer "In2.Cu")
		(net "M_B_CPU0_SB_CB<4>")
	)
	(arc
		(start 334.018636 -244.247162)
		(mid 333.744437 -244.171327)
		(end 333.467964 -244.238526)
		(width 0.088646)
		(layer "In2.Cu")
		(net "M_B_CPU0_SB_CB<4>")
	)
	(arc
		(start 334.393032 -244.247162)
		(mid 334.205834 -244.297305)
		(end 334.018636 -244.247162)
		(width 0.088646)
		(layer "In2.Cu")
		(net "M_B_CPU0_SB_CB<4>")
	)
	(arc
		(start 334.958436 -244.247162)
		(mid 334.684237 -244.171327)
		(end 334.407764 -244.238526)
		(width 0.088646)
		(layer "In2.Cu")
		(net "M_B_CPU0_SB_CB<4>")
	)
	(arc
		(start 335.898236 -244.247162)
		(mid 335.624037 -244.171327)
		(end 335.347564 -244.238526)
		(width 0.088646)
		(layer "In2.Cu")
		(net "M_B_CPU0_SB_CB<4>")
	)
	(arc
		(start 333.078836 -244.247162)
		(mid 332.804637 -244.171327)
		(end 332.528164 -244.238526)
		(width 0.088646)
		(layer "In2.Cu")
		(net "M_B_CPU0_SB_CB<4>")
	)
	(arc
		(start 336.272632 -244.247162)
		(mid 336.085434 -244.297305)
		(end 335.898236 -244.247162)
		(width 0.088646)
		(layer "In2.Cu")
		(net "M_B_CPU0_SB_CB<4>")
	)
	(arc
		(start 333.453232 -244.247162)
		(mid 333.266034 -244.297305)
		(end 333.078836 -244.247162)
		(width 0.088646)
		(layer "In2.Cu")
		(net "M_B_CPU0_SB_CB<4>")
	)
	(arc
		(start 332.513432 -244.247162)
		(mid 332.326234 -244.297305)
		(end 332.139036 -244.247162)
		(width 0.088646)
		(layer "In2.Cu")
		(net "M_B_CPU0_SB_CB<4>")
	)
	(segment
		(start 296.875962 -233.224324)
		(end 296.42943 -233.224324)
		(width 0.20066)
		(layer "F.Cu")
		(net "M_B_CPU0_SB_CB<3>")
	)
	(segment
		(start 292.689534 -233.441748)
		(end 292.67531 -233.455972)
		(width 0.101854)
		(layer "F.Cu")
		(net "M_B_CPU0_SB_CB<3>")
	)
	(segment
		(start 292.05301 -233.016806)
		(end 290.355782 -233.016806)
		(width 0.20066)
		(layer "F.Cu")
		(net "M_B_CPU0_SB_CB<3>")
	)
	(segment
		(start 292.178994 -233.313478)
		(end 292.178994 -233.14279)
		(width 0.20066)
		(layer "F.Cu")
		(net "M_B_CPU0_SB_CB<3>")
	)
	(segment
		(start 296.42943 -233.224324)
		(end 296.217594 -233.012488)
		(width 0.20066)
		(layer "F.Cu")
		(net "M_B_CPU0_SB_CB<3>")
	)
	(segment
		(start 299.004482 -233.016806)
		(end 297.899582 -233.016806)
		(width 0.20066)
		(layer "F.Cu")
		(net "M_B_CPU0_SB_CB<3>")
	)
	(segment
		(start 296.217594 -233.012488)
		(end 295.82237 -233.012488)
		(width 0.20066)
		(layer "F.Cu")
		(net "M_B_CPU0_SB_CB<3>")
	)
	(segment
		(start 295.000426 -233.441748)
		(end 292.927532 -233.441748)
		(width 0.1016)
		(layer "F.Cu")
		(net "M_B_CPU0_SB_CB<3>")
	)
	(segment
		(start 295.82237 -233.012488)
		(end 295.693846 -233.141012)
		(width 0.20066)
		(layer "F.Cu")
		(net "M_B_CPU0_SB_CB<3>")
	)
	(segment
		(start 295.693846 -233.29265)
		(end 295.544748 -233.441748)
		(width 0.20066)
		(layer "F.Cu")
		(net "M_B_CPU0_SB_CB<3>")
	)
	(segment
		(start 297.08348 -233.016806)
		(end 296.875962 -233.224324)
		(width 0.20066)
		(layer "F.Cu")
		(net "M_B_CPU0_SB_CB<3>")
	)
	(segment
		(start 297.899582 -233.016806)
		(end 297.08348 -233.016806)
		(width 0.20066)
		(layer "F.Cu")
		(net "M_B_CPU0_SB_CB<3>")
	)
	(segment
		(start 337.96478 -241.203226)
		(end 337.965034 -241.202972)
		(width 0.20066)
		(layer "F.Cu")
		(net "M_B_CPU0_SB_CB<3>")
	)
	(segment
		(start 295.544748 -233.441748)
		(end 295.000426 -233.441748)
		(width 0.20066)
		(layer "F.Cu")
		(net "M_B_CPU0_SB_CB<3>")
	)
	(segment
		(start 337.965034 -241.202972)
		(end 337.965034 -240.667286)
		(width 0.20066)
		(layer "F.Cu")
		(net "M_B_CPU0_SB_CB<3>")
	)
	(segment
		(start 292.321488 -233.455972)
		(end 292.178994 -233.313478)
		(width 0.20066)
		(layer "F.Cu")
		(net "M_B_CPU0_SB_CB<3>")
	)
	(segment
		(start 292.67531 -233.455972)
		(end 292.321488 -233.455972)
		(width 0.20066)
		(layer "F.Cu")
		(net "M_B_CPU0_SB_CB<3>")
	)
	(segment
		(start 292.178994 -233.14279)
		(end 292.05301 -233.016806)
		(width 0.20066)
		(layer "F.Cu")
		(net "M_B_CPU0_SB_CB<3>")
	)
	(segment
		(start 292.927532 -233.441748)
		(end 292.689534 -233.441748)
		(width 0.101854)
		(layer "F.Cu")
		(net "M_B_CPU0_SB_CB<3>")
	)
	(segment
		(start 295.693846 -233.141012)
		(end 295.693846 -233.29265)
		(width 0.20066)
		(layer "F.Cu")
		(net "M_B_CPU0_SB_CB<3>")
	)
	(segment
		(start 311.342532 -233.610404)
		(end 309.972202 -233.610404)
		(width 0.18288)
		(layer "In2.Cu")
		(net "M_B_CPU0_SB_CB<3>")
	)
	(segment
		(start 304.17135 -232.731818)
		(end 303.889664 -232.450132)
		(width 0.18288)
		(layer "In2.Cu")
		(net "M_B_CPU0_SB_CB<3>")
	)
	(segment
		(start 301.908464 -232.932478)
		(end 300.823376 -232.932478)
		(width 0.18288)
		(layer "In2.Cu")
		(net "M_B_CPU0_SB_CB<3>")
	)
	(segment
		(start 337.946238 -240.69929)
		(end 337.604354 -240.791238)
		(width 0.088646)
		(layer "In2.Cu")
		(net "M_B_CPU0_SB_CB<3>")
	)
	(segment
		(start 306.296822 -232.600754)
		(end 306.145946 -232.449878)
		(width 0.18288)
		(layer "In2.Cu")
		(net "M_B_CPU0_SB_CB<3>")
	)
	(segment
		(start 308.314852 -233.112056)
		(end 307.95087 -233.476038)
		(width 0.18288)
		(layer "In2.Cu")
		(net "M_B_CPU0_SB_CB<3>")
	)
	(segment
		(start 337.522312 -240.82375)
		(end 337.212432 -240.991644)
		(width 0.088646)
		(layer "In2.Cu")
		(net "M_B_CPU0_SB_CB<3>")
	)
	(segment
		(start 337.965034 -240.667286)
		(end 337.946238 -240.69929)
		(width 0.088646)
		(layer "In2.Cu")
		(net "M_B_CPU0_SB_CB<3>")
	)
	(segment
		(start 315.31687 -233.780838)
		(end 314.490354 -233.4387)
		(width 0.18288)
		(layer "In2.Cu")
		(net "M_B_CPU0_SB_CB<3>")
	)
	(segment
		(start 313.792108 -233.56316)
		(end 312.182256 -233.56316)
		(width 0.18288)
		(layer "In2.Cu")
		(net "M_B_CPU0_SB_CB<3>")
	)
	(segment
		(start 315.801248 -234.79125)
		(end 315.459618 -234.44962)
		(width 0.18288)
		(layer "In2.Cu")
		(net "M_B_CPU0_SB_CB<3>")
	)
	(segment
		(start 315.459618 -234.44962)
		(end 315.459618 -233.923586)
		(width 0.18288)
		(layer "In2.Cu")
		(net "M_B_CPU0_SB_CB<3>")
	)
	(segment
		(start 299.558456 -232.462832)
		(end 299.004482 -233.016806)
		(width 0.18288)
		(layer "In2.Cu")
		(net "M_B_CPU0_SB_CB<3>")
	)
	(segment
		(start 317.080646 -233.825288)
		(end 316.504066 -233.825288)
		(width 0.18288)
		(layer "In2.Cu")
		(net "M_B_CPU0_SB_CB<3>")
	)
	(segment
		(start 316.117986 -234.79125)
		(end 315.801248 -234.79125)
		(width 0.18288)
		(layer "In2.Cu")
		(net "M_B_CPU0_SB_CB<3>")
	)
	(segment
		(start 307.127656 -232.600754)
		(end 306.296822 -232.600754)
		(width 0.18288)
		(layer "In2.Cu")
		(net "M_B_CPU0_SB_CB<3>")
	)
	(segment
		(start 312.182256 -233.56316)
		(end 311.922668 -233.303572)
		(width 0.18288)
		(layer "In2.Cu")
		(net "M_B_CPU0_SB_CB<3>")
	)
	(segment
		(start 307.595016 -233.476038)
		(end 307.32095 -233.201972)
		(width 0.18288)
		(layer "In2.Cu")
		(net "M_B_CPU0_SB_CB<3>")
	)
	(segment
		(start 336.641694 -240.834926)
		(end 336.444336 -240.55959)
		(width 0.088646)
		(layer "In2.Cu")
		(net "M_B_CPU0_SB_CB<3>")
	)
	(segment
		(start 302.493172 -232.34777)
		(end 301.908464 -232.932478)
		(width 0.18288)
		(layer "In2.Cu")
		(net "M_B_CPU0_SB_CB<3>")
	)
	(segment
		(start 317.273686 -234.587542)
		(end 317.273686 -234.018328)
		(width 0.18288)
		(layer "In2.Cu")
		(net "M_B_CPU0_SB_CB<3>")
	)
	(segment
		(start 316.504066 -233.825288)
		(end 316.311026 -234.018328)
		(width 0.18288)
		(layer "In2.Cu")
		(net "M_B_CPU0_SB_CB<3>")
	)
	(segment
		(start 333.467964 -240.351564)
		(end 333.453232 -240.342928)
		(width 0.088646)
		(layer "In2.Cu")
		(net "M_B_CPU0_SB_CB<3>")
	)
	(segment
		(start 307.32095 -233.201972)
		(end 307.32095 -232.794048)
		(width 0.18288)
		(layer "In2.Cu")
		(net "M_B_CPU0_SB_CB<3>")
	)
	(segment
		(start 302.493172 -231.875838)
		(end 302.493172 -232.34777)
		(width 0.18288)
		(layer "In2.Cu")
		(net "M_B_CPU0_SB_CB<3>")
	)
	(segment
		(start 304.4444 -232.731818)
		(end 304.17135 -232.731818)
		(width 0.18288)
		(layer "In2.Cu")
		(net "M_B_CPU0_SB_CB<3>")
	)
	(segment
		(start 304.72634 -232.449878)
		(end 304.4444 -232.731818)
		(width 0.18288)
		(layer "In2.Cu")
		(net "M_B_CPU0_SB_CB<3>")
	)
	(segment
		(start 303.586642 -231.408224)
		(end 302.960786 -231.408224)
		(width 0.18288)
		(layer "In2.Cu")
		(net "M_B_CPU0_SB_CB<3>")
	)
	(segment
		(start 336.77352 -240.954306)
		(end 336.641694 -240.834926)
		(width 0.088646)
		(layer "In2.Cu")
		(net "M_B_CPU0_SB_CB<3>")
	)
	(segment
		(start 332.528164 -240.351564)
		(end 332.513432 -240.342928)
		(width 0.088646)
		(layer "In2.Cu")
		(net "M_B_CPU0_SB_CB<3>")
	)
	(segment
		(start 303.889664 -231.711246)
		(end 303.586642 -231.408224)
		(width 0.18288)
		(layer "In2.Cu")
		(net "M_B_CPU0_SB_CB<3>")
	)
	(segment
		(start 318.59093 -234.828588)
		(end 317.514732 -234.828588)
		(width 0.18288)
		(layer "In2.Cu")
		(net "M_B_CPU0_SB_CB<3>")
	)
	(segment
		(start 324.587108 -240.824766)
		(end 318.59093 -234.828588)
		(width 0.18288)
		(layer "In2.Cu")
		(net "M_B_CPU0_SB_CB<3>")
	)
	(segment
		(start 309.972202 -233.610404)
		(end 309.473854 -233.112056)
		(width 0.18288)
		(layer "In2.Cu")
		(net "M_B_CPU0_SB_CB<3>")
	)
	(segment
		(start 309.473854 -233.112056)
		(end 308.314852 -233.112056)
		(width 0.18288)
		(layer "In2.Cu")
		(net "M_B_CPU0_SB_CB<3>")
	)
	(segment
		(start 334.407764 -240.351564)
		(end 334.393032 -240.342928)
		(width 0.088646)
		(layer "In2.Cu")
		(net "M_B_CPU0_SB_CB<3>")
	)
	(segment
		(start 315.459618 -233.923586)
		(end 315.31687 -233.780838)
		(width 0.18288)
		(layer "In2.Cu")
		(net "M_B_CPU0_SB_CB<3>")
	)
	(segment
		(start 314.490354 -233.4387)
		(end 313.916568 -233.4387)
		(width 0.18288)
		(layer "In2.Cu")
		(net "M_B_CPU0_SB_CB<3>")
	)
	(segment
		(start 331.004164 -240.824766)
		(end 324.587108 -240.824766)
		(width 0.18288)
		(layer "In2.Cu")
		(net "M_B_CPU0_SB_CB<3>")
	)
	(segment
		(start 336.281522 -240.348008)
		(end 336.272632 -240.342928)
		(width 0.088646)
		(layer "In2.Cu")
		(net "M_B_CPU0_SB_CB<3>")
	)
	(segment
		(start 300.35373 -232.462832)
		(end 299.558456 -232.462832)
		(width 0.18288)
		(layer "In2.Cu")
		(net "M_B_CPU0_SB_CB<3>")
	)
	(segment
		(start 307.32095 -232.794048)
		(end 307.127656 -232.600754)
		(width 0.18288)
		(layer "In2.Cu")
		(net "M_B_CPU0_SB_CB<3>")
	)
	(segment
		(start 317.273686 -234.018328)
		(end 317.080646 -233.825288)
		(width 0.18288)
		(layer "In2.Cu")
		(net "M_B_CPU0_SB_CB<3>")
	)
	(segment
		(start 311.649364 -233.303572)
		(end 311.342532 -233.610404)
		(width 0.18288)
		(layer "In2.Cu")
		(net "M_B_CPU0_SB_CB<3>")
	)
	(segment
		(start 313.916568 -233.4387)
		(end 313.792108 -233.56316)
		(width 0.18288)
		(layer "In2.Cu")
		(net "M_B_CPU0_SB_CB<3>")
	)
	(segment
		(start 317.514732 -234.828588)
		(end 317.273686 -234.587542)
		(width 0.18288)
		(layer "In2.Cu")
		(net "M_B_CPU0_SB_CB<3>")
	)
	(segment
		(start 331.637894 -240.824766)
		(end 331.004164 -240.824766)
		(width 0.088646)
		(layer "In2.Cu")
		(net "M_B_CPU0_SB_CB<3>")
	)
	(segment
		(start 300.823376 -232.932478)
		(end 300.35373 -232.462832)
		(width 0.18288)
		(layer "In2.Cu")
		(net "M_B_CPU0_SB_CB<3>")
	)
	(segment
		(start 307.95087 -233.476038)
		(end 307.595016 -233.476038)
		(width 0.18288)
		(layer "In2.Cu")
		(net "M_B_CPU0_SB_CB<3>")
	)
	(segment
		(start 316.311026 -234.018328)
		(end 316.311026 -234.59821)
		(width 0.18288)
		(layer "In2.Cu")
		(net "M_B_CPU0_SB_CB<3>")
	)
	(segment
		(start 336.838036 -240.991644)
		(end 336.77352 -240.954306)
		(width 0.088646)
		(layer "In2.Cu")
		(net "M_B_CPU0_SB_CB<3>")
	)
	(segment
		(start 306.145946 -232.449878)
		(end 304.72634 -232.449878)
		(width 0.18288)
		(layer "In2.Cu")
		(net "M_B_CPU0_SB_CB<3>")
	)
	(segment
		(start 303.889664 -232.450132)
		(end 303.889664 -231.711246)
		(width 0.18288)
		(layer "In2.Cu")
		(net "M_B_CPU0_SB_CB<3>")
	)
	(segment
		(start 311.922668 -233.303572)
		(end 311.649364 -233.303572)
		(width 0.18288)
		(layer "In2.Cu")
		(net "M_B_CPU0_SB_CB<3>")
	)
	(segment
		(start 302.960786 -231.408224)
		(end 302.493172 -231.875838)
		(width 0.18288)
		(layer "In2.Cu")
		(net "M_B_CPU0_SB_CB<3>")
	)
	(segment
		(start 332.060804 -240.401856)
		(end 331.637894 -240.824766)
		(width 0.088646)
		(layer "In2.Cu")
		(net "M_B_CPU0_SB_CB<3>")
	)
	(segment
		(start 316.311026 -234.59821)
		(end 316.117986 -234.79125)
		(width 0.18288)
		(layer "In2.Cu")
		(net "M_B_CPU0_SB_CB<3>")
	)
	(segment
		(start 335.347564 -240.351564)
		(end 335.332832 -240.342928)
		(width 0.088646)
		(layer "In2.Cu")
		(net "M_B_CPU0_SB_CB<3>")
	)
	(arc
		(start 334.393032 -240.342928)
		(mid 334.205834 -240.292785)
		(end 334.018636 -240.342928)
		(width 0.088646)
		(layer "In2.Cu")
		(net "M_B_CPU0_SB_CB<3>")
	)
	(arc
		(start 332.139036 -240.342928)
		(mid 332.097978 -240.369815)
		(end 332.060804 -240.401856)
		(width 0.088646)
		(layer "In2.Cu")
		(net "M_B_CPU0_SB_CB<3>")
	)
	(arc
		(start 332.513432 -240.342928)
		(mid 332.326234 -240.292785)
		(end 332.139036 -240.342928)
		(width 0.088646)
		(layer "In2.Cu")
		(net "M_B_CPU0_SB_CB<3>")
	)
	(arc
		(start 334.018636 -240.342928)
		(mid 333.744407 -240.418853)
		(end 333.467964 -240.351564)
		(width 0.088646)
		(layer "In2.Cu")
		(net "M_B_CPU0_SB_CB<3>")
	)
	(arc
		(start 334.958436 -240.342928)
		(mid 334.684207 -240.418853)
		(end 334.407764 -240.351564)
		(width 0.088646)
		(layer "In2.Cu")
		(net "M_B_CPU0_SB_CB<3>")
	)
	(arc
		(start 335.332832 -240.342928)
		(mid 335.145634 -240.292785)
		(end 334.958436 -240.342928)
		(width 0.088646)
		(layer "In2.Cu")
		(net "M_B_CPU0_SB_CB<3>")
	)
	(arc
		(start 333.078836 -240.342928)
		(mid 332.804607 -240.418853)
		(end 332.528164 -240.351564)
		(width 0.088646)
		(layer "In2.Cu")
		(net "M_B_CPU0_SB_CB<3>")
	)
	(arc
		(start 337.212432 -240.991644)
		(mid 337.025234 -241.041787)
		(end 336.838036 -240.991644)
		(width 0.088646)
		(layer "In2.Cu")
		(net "M_B_CPU0_SB_CB<3>")
	)
	(arc
		(start 335.898236 -240.342928)
		(mid 335.624007 -240.418853)
		(end 335.347564 -240.351564)
		(width 0.088646)
		(layer "In2.Cu")
		(net "M_B_CPU0_SB_CB<3>")
	)
	(arc
		(start 333.453232 -240.342928)
		(mid 333.266034 -240.292785)
		(end 333.078836 -240.342928)
		(width 0.088646)
		(layer "In2.Cu")
		(net "M_B_CPU0_SB_CB<3>")
	)
	(arc
		(start 336.272632 -240.342928)
		(mid 336.085434 -240.292785)
		(end 335.898236 -240.342928)
		(width 0.088646)
		(layer "In2.Cu")
		(net "M_B_CPU0_SB_CB<3>")
	)
	(arc
		(start 336.444336 -240.55959)
		(mid 336.382394 -240.43883)
		(end 336.281522 -240.348008)
		(width 0.088646)
		(layer "In2.Cu")
		(net "M_B_CPU0_SB_CB<3>")
	)
	(arc
		(start 337.604354 -240.791238)
		(mid 337.562389 -240.805109)
		(end 337.522312 -240.82375)
		(width 0.088646)
		(layer "In2.Cu")
		(net "M_B_CPU0_SB_CB<3>")
	)
	(segment
		(start 292.940486 -234.291632)
		(end 292.68547 -234.291632)
		(width 0.101854)
		(layer "F.Cu")
		(net "M_B_CPU0_SB_CB<2>")
	)
	(segment
		(start 295.944544 -234.92841)
		(end 295.777158 -234.761024)
		(width 0.20066)
		(layer "F.Cu")
		(net "M_B_CPU0_SB_CB<2>")
	)
	(segment
		(start 296.373042 -234.92841)
		(end 295.944544 -234.92841)
		(width 0.20066)
		(layer "F.Cu")
		(net "M_B_CPU0_SB_CB<2>")
	)
	(segment
		(start 292.68547 -234.291632)
		(end 292.67531 -234.281472)
		(width 0.101854)
		(layer "F.Cu")
		(net "M_B_CPU0_SB_CB<2>")
	)
	(segment
		(start 292.67531 -234.281472)
		(end 291.937948 -234.281472)
		(width 0.20066)
		(layer "F.Cu")
		(net "M_B_CPU0_SB_CB<2>")
	)
	(segment
		(start 291.502846 -234.716574)
		(end 290.355782 -234.716574)
		(width 0.20066)
		(layer "F.Cu")
		(net "M_B_CPU0_SB_CB<2>")
	)
	(segment
		(start 295.777158 -234.435396)
		(end 295.633394 -234.291632)
		(width 0.20066)
		(layer "F.Cu")
		(net "M_B_CPU0_SB_CB<2>")
	)
	(segment
		(start 299.004482 -234.716574)
		(end 297.899582 -234.716574)
		(width 0.20066)
		(layer "F.Cu")
		(net "M_B_CPU0_SB_CB<2>")
	)
	(segment
		(start 291.937948 -234.281472)
		(end 291.502846 -234.716574)
		(width 0.20066)
		(layer "F.Cu")
		(net "M_B_CPU0_SB_CB<2>")
	)
	(segment
		(start 338.43468 -242.016788)
		(end 338.43468 -241.481102)
		(width 0.20066)
		(layer "F.Cu")
		(net "M_B_CPU0_SB_CB<2>")
	)
	(segment
		(start 296.584878 -234.716574)
		(end 296.373042 -234.92841)
		(width 0.20066)
		(layer "F.Cu")
		(net "M_B_CPU0_SB_CB<2>")
	)
	(segment
		(start 338.434934 -242.017042)
		(end 338.43468 -242.016788)
		(width 0.20066)
		(layer "F.Cu")
		(net "M_B_CPU0_SB_CB<2>")
	)
	(segment
		(start 295.000426 -234.291632)
		(end 292.940486 -234.291632)
		(width 0.1016)
		(layer "F.Cu")
		(net "M_B_CPU0_SB_CB<2>")
	)
	(segment
		(start 295.633394 -234.291632)
		(end 295.000426 -234.291632)
		(width 0.20066)
		(layer "F.Cu")
		(net "M_B_CPU0_SB_CB<2>")
	)
	(segment
		(start 295.777158 -234.761024)
		(end 295.777158 -234.435396)
		(width 0.20066)
		(layer "F.Cu")
		(net "M_B_CPU0_SB_CB<2>")
	)
	(segment
		(start 297.899582 -234.716574)
		(end 296.584878 -234.716574)
		(width 0.20066)
		(layer "F.Cu")
		(net "M_B_CPU0_SB_CB<2>")
	)
	(segment
		(start 304.32502 -234.344972)
		(end 304.165 -234.504992)
		(width 0.18288)
		(layer "In2.Cu")
		(net "M_B_CPU0_SB_CB<2>")
	)
	(segment
		(start 337.71078 -241.78895)
		(end 337.682332 -241.80546)
		(width 0.088646)
		(layer "In2.Cu")
		(net "M_B_CPU0_SB_CB<2>")
	)
	(segment
		(start 304.557176 -234.344972)
		(end 304.32502 -234.344972)
		(width 0.18288)
		(layer "In2.Cu")
		(net "M_B_CPU0_SB_CB<2>")
	)
	(segment
		(start 337.307682 -241.80546)
		(end 337.29295 -241.796824)
		(width 0.088646)
		(layer "In2.Cu")
		(net "M_B_CPU0_SB_CB<2>")
	)
	(segment
		(start 317.937896 -236.774482)
		(end 317.685928 -236.878876)
		(width 0.18288)
		(layer "In2.Cu")
		(net "M_B_CPU0_SB_CB<2>")
	)
	(segment
		(start 307.247544 -235.43641)
		(end 307.05425 -235.243116)
		(width 0.18288)
		(layer "In2.Cu")
		(net "M_B_CPU0_SB_CB<2>")
	)
	(segment
		(start 317.685928 -236.878876)
		(end 317.390018 -236.756194)
		(width 0.18288)
		(layer "In2.Cu")
		(net "M_B_CPU0_SB_CB<2>")
	)
	(segment
		(start 307.05425 -235.243116)
		(end 307.05425 -234.510072)
		(width 0.18288)
		(layer "In2.Cu")
		(net "M_B_CPU0_SB_CB<2>")
	)
	(segment
		(start 317.33998 -235.869734)
		(end 317.043816 -235.747052)
		(width 0.18288)
		(layer "In2.Cu")
		(net "M_B_CPU0_SB_CB<2>")
	)
	(segment
		(start 331.719682 -241.515646)
		(end 331.004164 -241.515646)
		(width 0.088646)
		(layer "In2.Cu")
		(net "M_B_CPU0_SB_CB<2>")
	)
	(segment
		(start 304.165 -234.984036)
		(end 304.00498 -235.144056)
		(width 0.18288)
		(layer "In2.Cu")
		(net "M_B_CPU0_SB_CB<2>")
	)
	(segment
		(start 337.307936 -241.80546)
		(end 337.307682 -241.80546)
		(width 0.088646)
		(layer "In2.Cu")
		(net "M_B_CPU0_SB_CB<2>")
	)
	(segment
		(start 300.524926 -234.27563)
		(end 300.42485 -234.175554)
		(width 0.18288)
		(layer "In2.Cu")
		(net "M_B_CPU0_SB_CB<2>")
	)
	(segment
		(start 316.634876 -236.228636)
		(end 316.382908 -236.33303)
		(width 0.18288)
		(layer "In2.Cu")
		(net "M_B_CPU0_SB_CB<2>")
	)
	(segment
		(start 307.702712 -235.43641)
		(end 307.247544 -235.43641)
		(width 0.18288)
		(layer "In2.Cu")
		(net "M_B_CPU0_SB_CB<2>")
	)
	(segment
		(start 303.128172 -234.951016)
		(end 303.128172 -234.314238)
		(width 0.18288)
		(layer "In2.Cu")
		(net "M_B_CPU0_SB_CB<2>")
	)
	(segment
		(start 304.92827 -233.973878)
		(end 304.557176 -234.344972)
		(width 0.18288)
		(layer "In2.Cu")
		(net "M_B_CPU0_SB_CB<2>")
	)
	(segment
		(start 317.44412 -236.121956)
		(end 317.33998 -235.869734)
		(width 0.18288)
		(layer "In2.Cu")
		(net "M_B_CPU0_SB_CB<2>")
	)
	(segment
		(start 302.3108 -234.27563)
		(end 300.524926 -234.27563)
		(width 0.18288)
		(layer "In2.Cu")
		(net "M_B_CPU0_SB_CB<2>")
	)
	(segment
		(start 300.42485 -234.175554)
		(end 299.545502 -234.175554)
		(width 0.18288)
		(layer "In2.Cu")
		(net "M_B_CPU0_SB_CB<2>")
	)
	(segment
		(start 318.334644 -236.321854)
		(end 318.082422 -236.425994)
		(width 0.18288)
		(layer "In2.Cu")
		(net "M_B_CPU0_SB_CB<2>")
	)
	(segment
		(start 314.706 -235.201714)
		(end 314.487814 -235.11129)
		(width 0.18288)
		(layer "In2.Cu")
		(net "M_B_CPU0_SB_CB<2>")
	)
	(segment
		(start 318.596264 -237.031276)
		(end 318.734948 -236.696758)
		(width 0.18288)
		(layer "In2.Cu")
		(net "M_B_CPU0_SB_CB<2>")
	)
	(segment
		(start 304.165 -234.504992)
		(end 304.165 -234.984036)
		(width 0.18288)
		(layer "In2.Cu")
		(net "M_B_CPU0_SB_CB<2>")
	)
	(segment
		(start 317.043816 -235.747052)
		(end 316.791594 -235.851192)
		(width 0.18288)
		(layer "In2.Cu")
		(net "M_B_CPU0_SB_CB<2>")
	)
	(segment
		(start 303.321212 -235.144056)
		(end 303.128172 -234.951016)
		(width 0.18288)
		(layer "In2.Cu")
		(net "M_B_CPU0_SB_CB<2>")
	)
	(segment
		(start 307.05425 -234.510072)
		(end 306.88915 -234.344972)
		(width 0.18288)
		(layer "In2.Cu")
		(net "M_B_CPU0_SB_CB<2>")
	)
	(segment
		(start 316.791594 -235.851192)
		(end 316.634876 -236.228636)
		(width 0.18288)
		(layer "In2.Cu")
		(net "M_B_CPU0_SB_CB<2>")
	)
	(segment
		(start 331.874876 -241.360452)
		(end 331.719682 -241.515646)
		(width 0.088646)
		(layer "In2.Cu")
		(net "M_B_CPU0_SB_CB<2>")
	)
	(segment
		(start 336.368136 -241.80546)
		(end 336.082132 -241.64036)
		(width 0.088646)
		(layer "In2.Cu")
		(net "M_B_CPU0_SB_CB<2>")
	)
	(segment
		(start 304.00498 -235.144056)
		(end 303.321212 -235.144056)
		(width 0.18288)
		(layer "In2.Cu")
		(net "M_B_CPU0_SB_CB<2>")
	)
	(segment
		(start 336.376518 -241.810286)
		(end 336.368136 -241.80546)
		(width 0.088646)
		(layer "In2.Cu")
		(net "M_B_CPU0_SB_CB<2>")
	)
	(segment
		(start 311.92343 -234.890818)
		(end 311.172352 -234.890818)
		(width 0.18288)
		(layer "In2.Cu")
		(net "M_B_CPU0_SB_CB<2>")
	)
	(segment
		(start 302.935132 -234.121198)
		(end 302.465232 -234.121198)
		(width 0.18288)
		(layer "In2.Cu")
		(net "M_B_CPU0_SB_CB<2>")
	)
	(segment
		(start 318.734948 -236.696758)
		(end 318.630554 -236.444536)
		(width 0.18288)
		(layer "In2.Cu")
		(net "M_B_CPU0_SB_CB<2>")
	)
	(segment
		(start 314.487814 -235.11129)
		(end 312.143902 -235.11129)
		(width 0.18288)
		(layer "In2.Cu")
		(net "M_B_CPU0_SB_CB<2>")
	)
	(segment
		(start 320.217292 -237.911894)
		(end 318.701928 -237.28553)
		(width 0.18288)
		(layer "In2.Cu")
		(net "M_B_CPU0_SB_CB<2>")
	)
	(segment
		(start 306.008786 -233.973878)
		(end 304.92827 -233.973878)
		(width 0.18288)
		(layer "In2.Cu")
		(net "M_B_CPU0_SB_CB<2>")
	)
	(segment
		(start 317.390018 -236.756194)
		(end 317.28537 -236.503972)
		(width 0.18288)
		(layer "In2.Cu")
		(net "M_B_CPU0_SB_CB<2>")
	)
	(segment
		(start 323.821044 -241.515646)
		(end 320.217292 -237.911894)
		(width 0.18288)
		(layer "In2.Cu")
		(net "M_B_CPU0_SB_CB<2>")
	)
	(segment
		(start 331.004164 -241.515646)
		(end 323.821044 -241.515646)
		(width 0.18288)
		(layer "In2.Cu")
		(net "M_B_CPU0_SB_CB<2>")
	)
	(segment
		(start 332.530958 -241.215926)
		(end 332.386432 -241.360452)
		(width 0.088646)
		(layer "In2.Cu")
		(net "M_B_CPU0_SB_CB<2>")
	)
	(segment
		(start 318.701928 -237.28553)
		(end 318.596264 -237.031276)
		(width 0.18288)
		(layer "In2.Cu")
		(net "M_B_CPU0_SB_CB<2>")
	)
	(segment
		(start 306.88915 -234.344972)
		(end 306.37988 -234.344972)
		(width 0.18288)
		(layer "In2.Cu")
		(net "M_B_CPU0_SB_CB<2>")
	)
	(segment
		(start 312.143902 -235.11129)
		(end 311.92343 -234.890818)
		(width 0.18288)
		(layer "In2.Cu")
		(net "M_B_CPU0_SB_CB<2>")
	)
	(segment
		(start 302.465232 -234.121198)
		(end 302.3108 -234.27563)
		(width 0.18288)
		(layer "In2.Cu")
		(net "M_B_CPU0_SB_CB<2>")
	)
	(segment
		(start 311.172352 -234.890818)
		(end 310.642 -235.42117)
		(width 0.18288)
		(layer "In2.Cu")
		(net "M_B_CPU0_SB_CB<2>")
	)
	(segment
		(start 332.386432 -241.360452)
		(end 331.874876 -241.360452)
		(width 0.088646)
		(layer "In2.Cu")
		(net "M_B_CPU0_SB_CB<2>")
	)
	(segment
		(start 338.43468 -241.481102)
		(end 337.71078 -241.78895)
		(width 0.088646)
		(layer "In2.Cu")
		(net "M_B_CPU0_SB_CB<2>")
	)
	(segment
		(start 310.062372 -235.42117)
		(end 309.556658 -234.915456)
		(width 0.18288)
		(layer "In2.Cu")
		(net "M_B_CPU0_SB_CB<2>")
	)
	(segment
		(start 316.382908 -236.33303)
		(end 314.923678 -235.728002)
		(width 0.18288)
		(layer "In2.Cu")
		(net "M_B_CPU0_SB_CB<2>")
	)
	(segment
		(start 310.642 -235.42117)
		(end 310.062372 -235.42117)
		(width 0.18288)
		(layer "In2.Cu")
		(net "M_B_CPU0_SB_CB<2>")
	)
	(segment
		(start 308.223666 -234.915456)
		(end 307.702712 -235.43641)
		(width 0.18288)
		(layer "In2.Cu")
		(net "M_B_CPU0_SB_CB<2>")
	)
	(segment
		(start 306.37988 -234.344972)
		(end 306.008786 -233.973878)
		(width 0.18288)
		(layer "In2.Cu")
		(net "M_B_CPU0_SB_CB<2>")
	)
	(segment
		(start 317.28537 -236.503972)
		(end 317.44412 -236.121956)
		(width 0.18288)
		(layer "In2.Cu")
		(net "M_B_CPU0_SB_CB<2>")
	)
	(segment
		(start 299.545502 -234.175554)
		(end 299.004482 -234.716574)
		(width 0.18288)
		(layer "In2.Cu")
		(net "M_B_CPU0_SB_CB<2>")
	)
	(segment
		(start 318.630554 -236.444536)
		(end 318.334644 -236.321854)
		(width 0.18288)
		(layer "In2.Cu")
		(net "M_B_CPU0_SB_CB<2>")
	)
	(segment
		(start 303.128172 -234.314238)
		(end 302.935132 -234.121198)
		(width 0.18288)
		(layer "In2.Cu")
		(net "M_B_CPU0_SB_CB<2>")
	)
	(segment
		(start 318.082422 -236.425994)
		(end 317.937896 -236.774482)
		(width 0.18288)
		(layer "In2.Cu")
		(net "M_B_CPU0_SB_CB<2>")
	)
	(segment
		(start 314.923678 -235.728002)
		(end 314.706 -235.201714)
		(width 0.18288)
		(layer "In2.Cu")
		(net "M_B_CPU0_SB_CB<2>")
	)
	(segment
		(start 309.556658 -234.915456)
		(end 308.223666 -234.915456)
		(width 0.18288)
		(layer "In2.Cu")
		(net "M_B_CPU0_SB_CB<2>")
	)
	(arc
		(start 336.082132 -241.64036)
		(mid 336.014643 -241.573113)
		(end 335.98993 -241.481102)
		(width 0.088646)
		(layer "In2.Cu")
		(net "M_B_CPU0_SB_CB<2>")
	)
	(arc
		(start 332.608936 -241.156744)
		(mid 332.568006 -241.183777)
		(end 332.530958 -241.215926)
		(width 0.088646)
		(layer "In2.Cu")
		(net "M_B_CPU0_SB_CB<2>")
	)
	(arc
		(start 336.742278 -241.80546)
		(mid 336.560027 -241.855571)
		(end 336.376518 -241.810286)
		(width 0.088646)
		(layer "In2.Cu")
		(net "M_B_CPU0_SB_CB<2>")
	)
	(arc
		(start 335.802732 -241.156744)
		(mid 335.615534 -241.106601)
		(end 335.428336 -241.156744)
		(width 0.088646)
		(layer "In2.Cu")
		(net "M_B_CPU0_SB_CB<2>")
	)
	(arc
		(start 335.98993 -241.481102)
		(mid 335.939776 -241.293846)
		(end 335.802732 -241.156744)
		(width 0.088646)
		(layer "In2.Cu")
		(net "M_B_CPU0_SB_CB<2>")
	)
	(arc
		(start 334.488536 -241.156744)
		(mid 334.205834 -241.23252)
		(end 333.923132 -241.156744)
		(width 0.088646)
		(layer "In2.Cu")
		(net "M_B_CPU0_SB_CB<2>")
	)
	(arc
		(start 333.923132 -241.156744)
		(mid 333.735934 -241.106601)
		(end 333.548736 -241.156744)
		(width 0.088646)
		(layer "In2.Cu")
		(net "M_B_CPU0_SB_CB<2>")
	)
	(arc
		(start 337.29295 -241.796824)
		(mid 337.016475 -241.729504)
		(end 336.742278 -241.80546)
		(width 0.088646)
		(layer "In2.Cu")
		(net "M_B_CPU0_SB_CB<2>")
	)
	(arc
		(start 333.548736 -241.156744)
		(mid 333.266034 -241.23252)
		(end 332.983332 -241.156744)
		(width 0.088646)
		(layer "In2.Cu")
		(net "M_B_CPU0_SB_CB<2>")
	)
	(arc
		(start 335.428336 -241.156744)
		(mid 335.145634 -241.23252)
		(end 334.862932 -241.156744)
		(width 0.088646)
		(layer "In2.Cu")
		(net "M_B_CPU0_SB_CB<2>")
	)
	(arc
		(start 332.983332 -241.156744)
		(mid 332.796134 -241.106601)
		(end 332.608936 -241.156744)
		(width 0.088646)
		(layer "In2.Cu")
		(net "M_B_CPU0_SB_CB<2>")
	)
	(arc
		(start 337.682332 -241.80546)
		(mid 337.495134 -241.855637)
		(end 337.307936 -241.80546)
		(width 0.088646)
		(layer "In2.Cu")
		(net "M_B_CPU0_SB_CB<2>")
	)
	(arc
		(start 334.862932 -241.156744)
		(mid 334.675734 -241.106601)
		(end 334.488536 -241.156744)
		(width 0.088646)
		(layer "In2.Cu")
		(net "M_B_CPU0_SB_CB<2>")
	)
	(segment
		(start 287.801304 -234.078018)
		(end 287.589976 -233.86669)
		(width 0.20066)
		(layer "F.Cu")
		(net "M_B_CPU0_SB_CB<1>")
	)
	(segment
		(start 337.025234 -241.202972)
		(end 337.025234 -240.667286)
		(width 0.20066)
		(layer "F.Cu")
		(net "M_B_CPU0_SB_CB<1>")
	)
	(segment
		(start 288.62274 -233.432858)
		(end 288.46018 -233.595418)
		(width 0.20066)
		(layer "F.Cu")
		(net "M_B_CPU0_SB_CB<1>")
	)
	(segment
		(start 288.46018 -233.923586)
		(end 288.305748 -234.078018)
		(width 0.20066)
		(layer "F.Cu")
		(net "M_B_CPU0_SB_CB<1>")
	)
	(segment
		(start 293.799514 -233.86669)
		(end 292.160198 -233.86669)
		(width 0.20066)
		(layer "F.Cu")
		(net "M_B_CPU0_SB_CB<1>")
	)
	(segment
		(start 291.735256 -233.441748)
		(end 291.556694 -233.441748)
		(width 0.20066)
		(layer "F.Cu")
		(net "M_B_CPU0_SB_CB<1>")
	)
	(segment
		(start 291.225986 -233.441748)
		(end 289.240468 -233.441748)
		(width 0.1016)
		(layer "F.Cu")
		(net "M_B_CPU0_SB_CB<1>")
	)
	(segment
		(start 289.240468 -233.441748)
		(end 289.231578 -233.432858)
		(width 0.1016)
		(layer "F.Cu")
		(net "M_B_CPU0_SB_CB<1>")
	)
	(segment
		(start 291.556694 -233.441748)
		(end 291.225986 -233.441748)
		(width 0.101854)
		(layer "F.Cu")
		(net "M_B_CPU0_SB_CB<1>")
	)
	(segment
		(start 288.46018 -233.595418)
		(end 288.46018 -233.923586)
		(width 0.20066)
		(layer "F.Cu")
		(net "M_B_CPU0_SB_CB<1>")
	)
	(segment
		(start 287.589976 -233.86669)
		(end 286.255714 -233.86669)
		(width 0.20066)
		(layer "F.Cu")
		(net "M_B_CPU0_SB_CB<1>")
	)
	(segment
		(start 289.231578 -233.432858)
		(end 288.62274 -233.432858)
		(width 0.20066)
		(layer "F.Cu")
		(net "M_B_CPU0_SB_CB<1>")
	)
	(segment
		(start 288.305748 -234.078018)
		(end 287.801304 -234.078018)
		(width 0.20066)
		(layer "F.Cu")
		(net "M_B_CPU0_SB_CB<1>")
	)
	(segment
		(start 337.02498 -241.203226)
		(end 337.025234 -241.202972)
		(width 0.20066)
		(layer "F.Cu")
		(net "M_B_CPU0_SB_CB<1>")
	)
	(segment
		(start 292.160198 -233.86669)
		(end 291.735256 -233.441748)
		(width 0.20066)
		(layer "F.Cu")
		(net "M_B_CPU0_SB_CB<1>")
	)
	(segment
		(start 294.904414 -233.86669)
		(end 293.799514 -233.86669)
		(width 0.20066)
		(layer "F.Cu")
		(net "M_B_CPU0_SB_CB<1>")
	)
	(segment
		(start 331.714094 -240.479326)
		(end 331.004164 -240.479326)
		(width 0.088646)
		(layer "In2.Cu")
		(net "M_B_CPU0_SB_CB<1>")
	)
	(segment
		(start 303.779936 -230.876856)
		(end 301.314104 -230.876856)
		(width 0.18288)
		(layer "In2.Cu")
		(net "M_B_CPU0_SB_CB<1>")
	)
	(segment
		(start 331.926184 -240.267236)
		(end 331.714094 -240.479326)
		(width 0.088646)
		(layer "In2.Cu")
		(net "M_B_CPU0_SB_CB<1>")
	)
	(segment
		(start 337.025234 -240.667286)
		(end 336.569812 -240.375694)
		(width 0.088646)
		(layer "In2.Cu")
		(net "M_B_CPU0_SB_CB<1>")
	)
	(segment
		(start 317.796164 -233.310938)
		(end 315.537596 -233.310938)
		(width 0.18288)
		(layer "In2.Cu")
		(net "M_B_CPU0_SB_CB<1>")
	)
	(segment
		(start 313.710574 -232.659174)
		(end 311.483248 -232.659174)
		(width 0.18288)
		(layer "In2.Cu")
		(net "M_B_CPU0_SB_CB<1>")
	)
	(segment
		(start 315.537596 -233.310938)
		(end 314.491116 -232.877868)
		(width 0.18288)
		(layer "In2.Cu")
		(net "M_B_CPU0_SB_CB<1>")
	)
	(segment
		(start 297.796204 -232.592372)
		(end 297.116754 -232.592372)
		(width 0.18288)
		(layer "In2.Cu")
		(net "M_B_CPU0_SB_CB<1>")
	)
	(segment
		(start 314.491116 -232.877868)
		(end 314.238894 -232.877868)
		(width 0.18288)
		(layer "In2.Cu")
		(net "M_B_CPU0_SB_CB<1>")
	)
	(segment
		(start 297.116754 -232.592372)
		(end 297.029124 -232.642918)
		(width 0.18288)
		(layer "In2.Cu")
		(net "M_B_CPU0_SB_CB<1>")
	)
	(segment
		(start 311.483248 -232.659174)
		(end 311.152286 -232.990136)
		(width 0.18288)
		(layer "In2.Cu")
		(net "M_B_CPU0_SB_CB<1>")
	)
	(segment
		(start 299.425106 -231.741726)
		(end 298.64685 -231.741726)
		(width 0.18288)
		(layer "In2.Cu")
		(net "M_B_CPU0_SB_CB<1>")
	)
	(segment
		(start 304.842164 -231.939084)
		(end 303.779936 -230.876856)
		(width 0.18288)
		(layer "In2.Cu")
		(net "M_B_CPU0_SB_CB<1>")
	)
	(segment
		(start 314.238894 -232.877868)
		(end 313.710574 -232.659174)
		(width 0.18288)
		(layer "In2.Cu")
		(net "M_B_CPU0_SB_CB<1>")
	)
	(segment
		(start 310.654446 -232.990136)
		(end 310.256174 -232.591864)
		(width 0.18288)
		(layer "In2.Cu")
		(net "M_B_CPU0_SB_CB<1>")
	)
	(segment
		(start 324.964552 -240.479326)
		(end 317.796164 -233.310938)
		(width 0.18288)
		(layer "In2.Cu")
		(net "M_B_CPU0_SB_CB<1>")
	)
	(segment
		(start 310.256174 -232.591864)
		(end 308.133242 -232.591864)
		(width 0.18288)
		(layer "In2.Cu")
		(net "M_B_CPU0_SB_CB<1>")
	)
	(segment
		(start 307.061108 -231.51973)
		(end 306.544218 -231.51973)
		(width 0.18288)
		(layer "In2.Cu")
		(net "M_B_CPU0_SB_CB<1>")
	)
	(segment
		(start 331.004164 -240.479326)
		(end 324.964552 -240.479326)
		(width 0.18288)
		(layer "In2.Cu")
		(net "M_B_CPU0_SB_CB<1>")
	)
	(segment
		(start 306.124864 -231.939084)
		(end 304.842164 -231.939084)
		(width 0.18288)
		(layer "In2.Cu")
		(net "M_B_CPU0_SB_CB<1>")
	)
	(segment
		(start 300.260004 -231.930956)
		(end 299.614336 -231.930956)
		(width 0.18288)
		(layer "In2.Cu")
		(net "M_B_CPU0_SB_CB<1>")
	)
	(segment
		(start 297.029124 -232.642918)
		(end 296.128186 -232.642918)
		(width 0.18288)
		(layer "In2.Cu")
		(net "M_B_CPU0_SB_CB<1>")
	)
	(segment
		(start 334.488282 -240.177574)
		(end 334.47355 -240.168938)
		(width 0.088646)
		(layer "In2.Cu")
		(net "M_B_CPU0_SB_CB<1>")
	)
	(segment
		(start 336.367882 -240.177574)
		(end 336.35315 -240.168938)
		(width 0.088646)
		(layer "In2.Cu")
		(net "M_B_CPU0_SB_CB<1>")
	)
	(segment
		(start 301.314104 -230.876856)
		(end 300.260004 -231.930956)
		(width 0.18288)
		(layer "In2.Cu")
		(net "M_B_CPU0_SB_CB<1>")
	)
	(segment
		(start 308.133242 -232.591864)
		(end 307.061108 -231.51973)
		(width 0.18288)
		(layer "In2.Cu")
		(net "M_B_CPU0_SB_CB<1>")
	)
	(segment
		(start 311.152286 -232.990136)
		(end 310.654446 -232.990136)
		(width 0.18288)
		(layer "In2.Cu")
		(net "M_B_CPU0_SB_CB<1>")
	)
	(segment
		(start 306.544218 -231.51973)
		(end 306.124864 -231.939084)
		(width 0.18288)
		(layer "In2.Cu")
		(net "M_B_CPU0_SB_CB<1>")
	)
	(segment
		(start 296.128186 -232.642918)
		(end 294.904414 -233.86669)
		(width 0.18288)
		(layer "In2.Cu")
		(net "M_B_CPU0_SB_CB<1>")
	)
	(segment
		(start 299.614336 -231.930956)
		(end 299.425106 -231.741726)
		(width 0.18288)
		(layer "In2.Cu")
		(net "M_B_CPU0_SB_CB<1>")
	)
	(segment
		(start 332.608682 -240.177574)
		(end 332.59395 -240.168938)
		(width 0.088646)
		(layer "In2.Cu")
		(net "M_B_CPU0_SB_CB<1>")
	)
	(segment
		(start 335.428082 -240.177574)
		(end 335.41335 -240.168938)
		(width 0.088646)
		(layer "In2.Cu")
		(net "M_B_CPU0_SB_CB<1>")
	)
	(segment
		(start 298.64685 -231.741726)
		(end 297.796204 -232.592372)
		(width 0.18288)
		(layer "In2.Cu")
		(net "M_B_CPU0_SB_CB<1>")
	)
	(segment
		(start 333.548482 -240.177574)
		(end 333.53375 -240.168938)
		(width 0.088646)
		(layer "In2.Cu")
		(net "M_B_CPU0_SB_CB<1>")
	)
	(arc
		(start 334.47355 -240.168938)
		(mid 334.197109 -240.101772)
		(end 333.922878 -240.177574)
		(width 0.088646)
		(layer "In2.Cu")
		(net "M_B_CPU0_SB_CB<1>")
	)
	(arc
		(start 332.043278 -240.177574)
		(mid 331.981793 -240.218569)
		(end 331.926184 -240.267236)
		(width 0.088646)
		(layer "In2.Cu")
		(net "M_B_CPU0_SB_CB<1>")
	)
	(arc
		(start 333.922878 -240.177574)
		(mid 333.73568 -240.227717)
		(end 333.548482 -240.177574)
		(width 0.088646)
		(layer "In2.Cu")
		(net "M_B_CPU0_SB_CB<1>")
	)
	(arc
		(start 333.53375 -240.168938)
		(mid 333.257309 -240.101772)
		(end 332.983078 -240.177574)
		(width 0.088646)
		(layer "In2.Cu")
		(net "M_B_CPU0_SB_CB<1>")
	)
	(arc
		(start 335.41335 -240.168938)
		(mid 335.136909 -240.101772)
		(end 334.862678 -240.177574)
		(width 0.088646)
		(layer "In2.Cu")
		(net "M_B_CPU0_SB_CB<1>")
	)
	(arc
		(start 335.802478 -240.177574)
		(mid 335.61528 -240.227717)
		(end 335.428082 -240.177574)
		(width 0.088646)
		(layer "In2.Cu")
		(net "M_B_CPU0_SB_CB<1>")
	)
	(arc
		(start 332.59395 -240.168938)
		(mid 332.317509 -240.101772)
		(end 332.043278 -240.177574)
		(width 0.088646)
		(layer "In2.Cu")
		(net "M_B_CPU0_SB_CB<1>")
	)
	(arc
		(start 334.862678 -240.177574)
		(mid 334.67548 -240.227717)
		(end 334.488282 -240.177574)
		(width 0.088646)
		(layer "In2.Cu")
		(net "M_B_CPU0_SB_CB<1>")
	)
	(arc
		(start 336.35315 -240.168938)
		(mid 336.076709 -240.101772)
		(end 335.802478 -240.177574)
		(width 0.088646)
		(layer "In2.Cu")
		(net "M_B_CPU0_SB_CB<1>")
	)
	(arc
		(start 336.569812 -240.375694)
		(mid 336.481454 -240.263781)
		(end 336.367882 -240.177574)
		(width 0.088646)
		(layer "In2.Cu")
		(net "M_B_CPU0_SB_CB<1>")
	)
	(arc
		(start 332.983078 -240.177574)
		(mid 332.79588 -240.227717)
		(end 332.608682 -240.177574)
		(width 0.088646)
		(layer "In2.Cu")
		(net "M_B_CPU0_SB_CB<1>")
	)
	(segment
		(start 288.46018 -235.343192)
		(end 288.46018 -235.632752)
		(width 0.20066)
		(layer "F.Cu")
		(net "M_B_CPU0_SB_CB<0>")
	)
	(segment
		(start 293.799514 -235.566712)
		(end 292.430454 -235.566712)
		(width 0.20066)
		(layer "F.Cu")
		(net "M_B_CPU0_SB_CB<0>")
	)
	(segment
		(start 336.55508 -242.016788)
		(end 336.55508 -241.481102)
		(width 0.20066)
		(layer "F.Cu")
		(net "M_B_CPU0_SB_CB<0>")
	)
	(segment
		(start 288.28746 -235.805472)
		(end 287.828736 -235.805472)
		(width 0.20066)
		(layer "F.Cu")
		(net "M_B_CPU0_SB_CB<0>")
	)
	(segment
		(start 294.904414 -235.566712)
		(end 293.799514 -235.566712)
		(width 0.20066)
		(layer "F.Cu")
		(net "M_B_CPU0_SB_CB<0>")
	)
	(segment
		(start 289.239706 -235.14177)
		(end 289.231578 -235.133642)
		(width 0.101854)
		(layer "F.Cu")
		(net "M_B_CPU0_SB_CB<0>")
	)
	(segment
		(start 287.589976 -235.566712)
		(end 286.255714 -235.566712)
		(width 0.20066)
		(layer "F.Cu")
		(net "M_B_CPU0_SB_CB<0>")
	)
	(segment
		(start 291.556694 -235.14177)
		(end 289.48761 -235.14177)
		(width 0.1016)
		(layer "F.Cu")
		(net "M_B_CPU0_SB_CB<0>")
	)
	(segment
		(start 289.48761 -235.14177)
		(end 289.239706 -235.14177)
		(width 0.101854)
		(layer "F.Cu")
		(net "M_B_CPU0_SB_CB<0>")
	)
	(segment
		(start 336.555334 -242.017042)
		(end 336.55508 -242.016788)
		(width 0.20066)
		(layer "F.Cu")
		(net "M_B_CPU0_SB_CB<0>")
	)
	(segment
		(start 288.46018 -235.632752)
		(end 288.28746 -235.805472)
		(width 0.20066)
		(layer "F.Cu")
		(net "M_B_CPU0_SB_CB<0>")
	)
	(segment
		(start 292.430454 -235.566712)
		(end 292.005512 -235.14177)
		(width 0.20066)
		(layer "F.Cu")
		(net "M_B_CPU0_SB_CB<0>")
	)
	(segment
		(start 289.231578 -235.133642)
		(end 288.66973 -235.133642)
		(width 0.20066)
		(layer "F.Cu")
		(net "M_B_CPU0_SB_CB<0>")
	)
	(segment
		(start 288.66973 -235.133642)
		(end 288.46018 -235.343192)
		(width 0.20066)
		(layer "F.Cu")
		(net "M_B_CPU0_SB_CB<0>")
	)
	(segment
		(start 287.828736 -235.805472)
		(end 287.589976 -235.566712)
		(width 0.20066)
		(layer "F.Cu")
		(net "M_B_CPU0_SB_CB<0>")
	)
	(segment
		(start 292.005512 -235.14177)
		(end 291.556694 -235.14177)
		(width 0.20066)
		(layer "F.Cu")
		(net "M_B_CPU0_SB_CB<0>")
	)
	(segment
		(start 311.087262 -234.375452)
		(end 310.831992 -234.120182)
		(width 0.18288)
		(layer "In2.Cu")
		(net "M_B_CPU0_SB_CB<0>")
	)
	(segment
		(start 303.072292 -232.762044)
		(end 302.879252 -232.955084)
		(width 0.18288)
		(layer "In2.Cu")
		(net "M_B_CPU0_SB_CB<0>")
	)
	(segment
		(start 313.638184 -234.07116)
		(end 312.36412 -234.07116)
		(width 0.18288)
		(layer "In2.Cu")
		(net "M_B_CPU0_SB_CB<0>")
	)
	(segment
		(start 316.16142 -235.561378)
		(end 315.961014 -235.561378)
		(width 0.18288)
		(layer "In2.Cu")
		(net "M_B_CPU0_SB_CB<0>")
	)
	(segment
		(start 331.004164 -241.170206)
		(end 324.204076 -241.170206)
		(width 0.18288)
		(layer "In2.Cu")
		(net "M_B_CPU0_SB_CB<0>")
	)
	(segment
		(start 307.361082 -234.026456)
		(end 306.739798 -233.405172)
		(width 0.18288)
		(layer "In2.Cu")
		(net "M_B_CPU0_SB_CB<0>")
	)
	(segment
		(start 314.87999 -234.588558)
		(end 314.155582 -234.588558)
		(width 0.18288)
		(layer "In2.Cu")
		(net "M_B_CPU0_SB_CB<0>")
	)
	(segment
		(start 295.766998 -234.704128)
		(end 295.766998 -235.373672)
		(width 0.18288)
		(layer "In2.Cu")
		(net "M_B_CPU0_SB_CB<0>")
	)
	(segment
		(start 319.755012 -237.1344)
		(end 319.239392 -236.61878)
		(width 0.18288)
		(layer "In2.Cu")
		(net "M_B_CPU0_SB_CB<0>")
	)
	(segment
		(start 299.416724 -233.64825)
		(end 299.210222 -233.441748)
		(width 0.18288)
		(layer "In2.Cu")
		(net "M_B_CPU0_SB_CB<0>")
	)
	(segment
		(start 314.155582 -234.588558)
		(end 313.638184 -234.07116)
		(width 0.18288)
		(layer "In2.Cu")
		(net "M_B_CPU0_SB_CB<0>")
	)
	(segment
		(start 312.36412 -234.07116)
		(end 312.059828 -234.375452)
		(width 0.18288)
		(layer "In2.Cu")
		(net "M_B_CPU0_SB_CB<0>")
	)
	(segment
		(start 307.829458 -234.026456)
		(end 307.361082 -234.026456)
		(width 0.18288)
		(layer "In2.Cu")
		(net "M_B_CPU0_SB_CB<0>")
	)
	(segment
		(start 309.89143 -234.120182)
		(end 309.611776 -234.399836)
		(width 0.18288)
		(layer "In2.Cu")
		(net "M_B_CPU0_SB_CB<0>")
	)
	(segment
		(start 319.239392 -236.61878)
		(end 319.239392 -236.213142)
		(width 0.18288)
		(layer "In2.Cu")
		(net "M_B_CPU0_SB_CB<0>")
	)
	(segment
		(start 303.846992 -233.405172)
		(end 303.653952 -233.212132)
		(width 0.18288)
		(layer "In2.Cu")
		(net "M_B_CPU0_SB_CB<0>")
	)
	(segment
		(start 302.182784 -233.44251)
		(end 300.572932 -233.44251)
		(width 0.18288)
		(layer "In2.Cu")
		(net "M_B_CPU0_SB_CB<0>")
	)
	(segment
		(start 318.471296 -235.787946)
		(end 317.14186 -235.237528)
		(width 0.18288)
		(layer "In2.Cu")
		(net "M_B_CPU0_SB_CB<0>")
	)
	(segment
		(start 302.686212 -233.560366)
		(end 302.30064 -233.560366)
		(width 0.18288)
		(layer "In2.Cu")
		(net "M_B_CPU0_SB_CB<0>")
	)
	(segment
		(start 295.573958 -235.566712)
		(end 294.904414 -235.566712)
		(width 0.18288)
		(layer "In2.Cu")
		(net "M_B_CPU0_SB_CB<0>")
	)
	(segment
		(start 315.776102 -235.48467)
		(end 314.87999 -234.588558)
		(width 0.18288)
		(layer "In2.Cu")
		(net "M_B_CPU0_SB_CB<0>")
	)
	(segment
		(start 319.239392 -236.213142)
		(end 318.814196 -235.787946)
		(width 0.18288)
		(layer "In2.Cu")
		(net "M_B_CPU0_SB_CB<0>")
	)
	(segment
		(start 318.814196 -235.787946)
		(end 318.471296 -235.787946)
		(width 0.18288)
		(layer "In2.Cu")
		(net "M_B_CPU0_SB_CB<0>")
	)
	(segment
		(start 316.94628 -235.237528)
		(end 316.16142 -235.561378)
		(width 0.18288)
		(layer "In2.Cu")
		(net "M_B_CPU0_SB_CB<0>")
	)
	(segment
		(start 335.92643 -241.007646)
		(end 335.898236 -240.991644)
		(width 0.088646)
		(layer "In2.Cu")
		(net "M_B_CPU0_SB_CB<0>")
	)
	(segment
		(start 300.367192 -233.64825)
		(end 299.416724 -233.64825)
		(width 0.18288)
		(layer "In2.Cu")
		(net "M_B_CPU0_SB_CB<0>")
	)
	(segment
		(start 336.55508 -241.481102)
		(end 335.92643 -241.007646)
		(width 0.088646)
		(layer "In2.Cu")
		(net "M_B_CPU0_SB_CB<0>")
	)
	(segment
		(start 297.889422 -233.441748)
		(end 296.85742 -234.47375)
		(width 0.18288)
		(layer "In2.Cu")
		(net "M_B_CPU0_SB_CB<0>")
	)
	(segment
		(start 295.766998 -235.373672)
		(end 295.573958 -235.566712)
		(width 0.18288)
		(layer "In2.Cu")
		(net "M_B_CPU0_SB_CB<0>")
	)
	(segment
		(start 324.204076 -241.170206)
		(end 320.16827 -237.1344)
		(width 0.18288)
		(layer "In2.Cu")
		(net "M_B_CPU0_SB_CB<0>")
	)
	(segment
		(start 302.879252 -232.955084)
		(end 302.879252 -233.367326)
		(width 0.18288)
		(layer "In2.Cu")
		(net "M_B_CPU0_SB_CB<0>")
	)
	(segment
		(start 306.739798 -233.405172)
		(end 303.846992 -233.405172)
		(width 0.18288)
		(layer "In2.Cu")
		(net "M_B_CPU0_SB_CB<0>")
	)
	(segment
		(start 317.14186 -235.237528)
		(end 316.94628 -235.237528)
		(width 0.18288)
		(layer "In2.Cu")
		(net "M_B_CPU0_SB_CB<0>")
	)
	(segment
		(start 315.961014 -235.561378)
		(end 315.776102 -235.48467)
		(width 0.18288)
		(layer "In2.Cu")
		(net "M_B_CPU0_SB_CB<0>")
	)
	(segment
		(start 332.396338 -241.081306)
		(end 332.307438 -241.170206)
		(width 0.088646)
		(layer "In2.Cu")
		(net "M_B_CPU0_SB_CB<0>")
	)
	(segment
		(start 303.460912 -232.762044)
		(end 303.072292 -232.762044)
		(width 0.18288)
		(layer "In2.Cu")
		(net "M_B_CPU0_SB_CB<0>")
	)
	(segment
		(start 303.653952 -232.955084)
		(end 303.460912 -232.762044)
		(width 0.18288)
		(layer "In2.Cu")
		(net "M_B_CPU0_SB_CB<0>")
	)
	(segment
		(start 320.16827 -237.1344)
		(end 319.755012 -237.1344)
		(width 0.18288)
		(layer "In2.Cu")
		(net "M_B_CPU0_SB_CB<0>")
	)
	(segment
		(start 299.210222 -233.441748)
		(end 297.889422 -233.441748)
		(width 0.18288)
		(layer "In2.Cu")
		(net "M_B_CPU0_SB_CB<0>")
	)
	(segment
		(start 309.611776 -234.399836)
		(end 308.202838 -234.399836)
		(width 0.18288)
		(layer "In2.Cu")
		(net "M_B_CPU0_SB_CB<0>")
	)
	(segment
		(start 332.307438 -241.170206)
		(end 331.004164 -241.170206)
		(width 0.088646)
		(layer "In2.Cu")
		(net "M_B_CPU0_SB_CB<0>")
	)
	(segment
		(start 308.202838 -234.399836)
		(end 307.829458 -234.026456)
		(width 0.18288)
		(layer "In2.Cu")
		(net "M_B_CPU0_SB_CB<0>")
	)
	(segment
		(start 310.831992 -234.120182)
		(end 309.89143 -234.120182)
		(width 0.18288)
		(layer "In2.Cu")
		(net "M_B_CPU0_SB_CB<0>")
	)
	(segment
		(start 296.85742 -234.47375)
		(end 295.997376 -234.47375)
		(width 0.18288)
		(layer "In2.Cu")
		(net "M_B_CPU0_SB_CB<0>")
	)
	(segment
		(start 302.30064 -233.560366)
		(end 302.182784 -233.44251)
		(width 0.18288)
		(layer "In2.Cu")
		(net "M_B_CPU0_SB_CB<0>")
	)
	(segment
		(start 300.572932 -233.44251)
		(end 300.367192 -233.64825)
		(width 0.18288)
		(layer "In2.Cu")
		(net "M_B_CPU0_SB_CB<0>")
	)
	(segment
		(start 312.059828 -234.375452)
		(end 311.087262 -234.375452)
		(width 0.18288)
		(layer "In2.Cu")
		(net "M_B_CPU0_SB_CB<0>")
	)
	(segment
		(start 302.879252 -233.367326)
		(end 302.686212 -233.560366)
		(width 0.18288)
		(layer "In2.Cu")
		(net "M_B_CPU0_SB_CB<0>")
	)
	(segment
		(start 303.653952 -233.212132)
		(end 303.653952 -232.955084)
		(width 0.18288)
		(layer "In2.Cu")
		(net "M_B_CPU0_SB_CB<0>")
	)
	(segment
		(start 295.997376 -234.47375)
		(end 295.766998 -234.704128)
		(width 0.18288)
		(layer "In2.Cu")
		(net "M_B_CPU0_SB_CB<0>")
	)
	(arc
		(start 332.513432 -240.991644)
		(mid 332.451954 -241.032646)
		(end 332.396338 -241.081306)
		(width 0.088646)
		(layer "In2.Cu")
		(net "M_B_CPU0_SB_CB<0>")
	)
	(arc
		(start 335.332832 -240.991644)
		(mid 335.145634 -241.041787)
		(end 334.958436 -240.991644)
		(width 0.088646)
		(layer "In2.Cu")
		(net "M_B_CPU0_SB_CB<0>")
	)
	(arc
		(start 334.018636 -240.991644)
		(mid 333.735934 -240.915868)
		(end 333.453232 -240.991644)
		(width 0.088646)
		(layer "In2.Cu")
		(net "M_B_CPU0_SB_CB<0>")
	)
	(arc
		(start 333.453232 -240.991644)
		(mid 333.266034 -241.041787)
		(end 333.078836 -240.991644)
		(width 0.088646)
		(layer "In2.Cu")
		(net "M_B_CPU0_SB_CB<0>")
	)
	(arc
		(start 334.958436 -240.991644)
		(mid 334.675734 -240.915868)
		(end 334.393032 -240.991644)
		(width 0.088646)
		(layer "In2.Cu")
		(net "M_B_CPU0_SB_CB<0>")
	)
	(arc
		(start 334.393032 -240.991644)
		(mid 334.205834 -241.041787)
		(end 334.018636 -240.991644)
		(width 0.088646)
		(layer "In2.Cu")
		(net "M_B_CPU0_SB_CB<0>")
	)
	(arc
		(start 333.078836 -240.991644)
		(mid 332.796134 -240.915868)
		(end 332.513432 -240.991644)
		(width 0.088646)
		(layer "In2.Cu")
		(net "M_B_CPU0_SB_CB<0>")
	)
	(arc
		(start 335.898236 -240.991644)
		(mid 335.615534 -240.915868)
		(end 335.332832 -240.991644)
		(width 0.088646)
		(layer "In2.Cu")
		(net "M_B_CPU0_SB_CB<0>")
	)
	(segment
		(start 292.160198 -247.466612)
		(end 291.735256 -247.04167)
		(width 0.20066)
		(layer "F.Cu")
		(net "M_B_CPU0_SB_CA<6>")
	)
	(segment
		(start 293.799514 -247.466612)
		(end 292.160198 -247.466612)
		(width 0.20066)
		(layer "F.Cu")
		(net "M_B_CPU0_SB_CA<6>")
	)
	(segment
		(start 288.62274 -247.03278)
		(end 288.46018 -247.19534)
		(width 0.20066)
		(layer "F.Cu")
		(net "M_B_CPU0_SB_CA<6>")
	)
	(segment
		(start 289.231578 -247.03278)
		(end 288.62274 -247.03278)
		(width 0.20066)
		(layer "F.Cu")
		(net "M_B_CPU0_SB_CA<6>")
	)
	(segment
		(start 288.305748 -247.67794)
		(end 287.801304 -247.67794)
		(width 0.20066)
		(layer "F.Cu")
		(net "M_B_CPU0_SB_CA<6>")
	)
	(segment
		(start 291.225986 -247.04167)
		(end 289.240468 -247.04167)
		(width 0.1016)
		(layer "F.Cu")
		(net "M_B_CPU0_SB_CA<6>")
	)
	(segment
		(start 336.085434 -247.714262)
		(end 336.085434 -247.178322)
		(width 0.20066)
		(layer "F.Cu")
		(net "M_B_CPU0_SB_CA<6>")
	)
	(segment
		(start 291.556694 -247.04167)
		(end 291.225986 -247.04167)
		(width 0.101854)
		(layer "F.Cu")
		(net "M_B_CPU0_SB_CA<6>")
	)
	(segment
		(start 288.46018 -247.523508)
		(end 288.305748 -247.67794)
		(width 0.20066)
		(layer "F.Cu")
		(net "M_B_CPU0_SB_CA<6>")
	)
	(segment
		(start 287.801304 -247.67794)
		(end 287.589976 -247.466612)
		(width 0.20066)
		(layer "F.Cu")
		(net "M_B_CPU0_SB_CA<6>")
	)
	(segment
		(start 291.735256 -247.04167)
		(end 291.556694 -247.04167)
		(width 0.20066)
		(layer "F.Cu")
		(net "M_B_CPU0_SB_CA<6>")
	)
	(segment
		(start 287.589976 -247.466612)
		(end 286.255714 -247.466612)
		(width 0.20066)
		(layer "F.Cu")
		(net "M_B_CPU0_SB_CA<6>")
	)
	(segment
		(start 288.46018 -247.19534)
		(end 288.46018 -247.523508)
		(width 0.20066)
		(layer "F.Cu")
		(net "M_B_CPU0_SB_CA<6>")
	)
	(segment
		(start 289.240468 -247.04167)
		(end 289.231578 -247.03278)
		(width 0.1016)
		(layer "F.Cu")
		(net "M_B_CPU0_SB_CA<6>")
	)
	(segment
		(start 294.904414 -247.466612)
		(end 293.799514 -247.466612)
		(width 0.20066)
		(layer "F.Cu")
		(net "M_B_CPU0_SB_CA<6>")
	)
	(segment
		(start 297.368722 -247.260364)
		(end 297.368722 -247.732042)
		(width 0.18288)
		(layer "In2.Cu")
		(net "M_B_CPU0_SB_CA<6>")
	)
	(segment
		(start 308.068472 -247.880886)
		(end 307.92547 -247.737884)
		(width 0.18288)
		(layer "In2.Cu")
		(net "M_B_CPU0_SB_CA<6>")
	)
	(segment
		(start 320.221102 -248.842276)
		(end 320.028062 -248.649236)
		(width 0.18288)
		(layer "In2.Cu")
		(net "M_B_CPU0_SB_CA<6>")
	)
	(segment
		(start 331.348842 -246.929656)
		(end 331.329792 -246.910606)
		(width 0.088646)
		(layer "In2.Cu")
		(net "M_B_CPU0_SB_CA<6>")
	)
	(segment
		(start 306.76088 -247.922542)
		(end 303.485804 -247.922542)
		(width 0.18288)
		(layer "In2.Cu")
		(net "M_B_CPU0_SB_CA<6>")
	)
	(segment
		(start 295.292526 -247.466612)
		(end 294.904414 -247.466612)
		(width 0.18288)
		(layer "In2.Cu")
		(net "M_B_CPU0_SB_CA<6>")
	)
	(segment
		(start 322.559426 -246.910606)
		(end 321.54368 -247.926352)
		(width 0.18288)
		(layer "In2.Cu")
		(net "M_B_CPU0_SB_CA<6>")
	)
	(segment
		(start 297.368722 -247.732042)
		(end 297.18127 -247.919494)
		(width 0.18288)
		(layer "In2.Cu")
		(net "M_B_CPU0_SB_CA<6>")
	)
	(segment
		(start 295.485566 -247.659652)
		(end 295.292526 -247.466612)
		(width 0.18288)
		(layer "In2.Cu")
		(net "M_B_CPU0_SB_CA<6>")
	)
	(segment
		(start 307.92547 -247.737884)
		(end 306.945538 -247.737884)
		(width 0.18288)
		(layer "In2.Cu")
		(net "M_B_CPU0_SB_CA<6>")
	)
	(segment
		(start 319.835022 -247.926352)
		(end 313.850528 -247.926352)
		(width 0.18288)
		(layer "In2.Cu")
		(net "M_B_CPU0_SB_CA<6>")
	)
	(segment
		(start 306.945538 -247.737884)
		(end 306.76088 -247.922542)
		(width 0.18288)
		(layer "In2.Cu")
		(net "M_B_CPU0_SB_CA<6>")
	)
	(segment
		(start 312.114946 -247.92051)
		(end 311.612788 -247.92051)
		(width 0.18288)
		(layer "In2.Cu")
		(net "M_B_CPU0_SB_CA<6>")
	)
	(segment
		(start 296.293794 -248.987818)
		(end 296.133774 -249.147838)
		(width 0.18288)
		(layer "In2.Cu")
		(net "M_B_CPU0_SB_CA<6>")
	)
	(segment
		(start 313.850528 -247.926352)
		(end 313.556396 -247.63222)
		(width 0.18288)
		(layer "In2.Cu")
		(net "M_B_CPU0_SB_CA<6>")
	)
	(segment
		(start 296.293794 -248.079514)
		(end 296.293794 -248.987818)
		(width 0.18288)
		(layer "In2.Cu")
		(net "M_B_CPU0_SB_CA<6>")
	)
	(segment
		(start 297.5864 -247.042686)
		(end 297.368722 -247.260364)
		(width 0.18288)
		(layer "In2.Cu")
		(net "M_B_CPU0_SB_CA<6>")
	)
	(segment
		(start 309.963058 -247.695974)
		(end 309.778146 -247.880886)
		(width 0.18288)
		(layer "In2.Cu")
		(net "M_B_CPU0_SB_CA<6>")
	)
	(segment
		(start 320.734182 -248.649236)
		(end 320.541142 -248.842276)
		(width 0.18288)
		(layer "In2.Cu")
		(net "M_B_CPU0_SB_CA<6>")
	)
	(segment
		(start 331.856334 -246.929656)
		(end 331.348842 -246.929656)
		(width 0.088646)
		(layer "In2.Cu")
		(net "M_B_CPU0_SB_CA<6>")
	)
	(segment
		(start 303.485804 -247.922542)
		(end 303.150016 -247.586754)
		(width 0.18288)
		(layer "In2.Cu")
		(net "M_B_CPU0_SB_CA<6>")
	)
	(segment
		(start 296.133774 -249.147838)
		(end 295.678606 -249.147838)
		(width 0.18288)
		(layer "In2.Cu")
		(net "M_B_CPU0_SB_CA<6>")
	)
	(segment
		(start 295.678606 -249.147838)
		(end 295.485566 -248.954798)
		(width 0.18288)
		(layer "In2.Cu")
		(net "M_B_CPU0_SB_CA<6>")
	)
	(segment
		(start 320.734182 -248.119392)
		(end 320.734182 -248.649236)
		(width 0.18288)
		(layer "In2.Cu")
		(net "M_B_CPU0_SB_CA<6>")
	)
	(segment
		(start 299.187108 -247.042686)
		(end 297.5864 -247.042686)
		(width 0.18288)
		(layer "In2.Cu")
		(net "M_B_CPU0_SB_CA<6>")
	)
	(segment
		(start 302.142144 -247.934988)
		(end 300.560232 -247.934988)
		(width 0.18288)
		(layer "In2.Cu")
		(net "M_B_CPU0_SB_CA<6>")
	)
	(segment
		(start 299.827442 -247.68302)
		(end 299.187108 -247.042686)
		(width 0.18288)
		(layer "In2.Cu")
		(net "M_B_CPU0_SB_CA<6>")
	)
	(segment
		(start 302.490378 -247.586754)
		(end 302.142144 -247.934988)
		(width 0.18288)
		(layer "In2.Cu")
		(net "M_B_CPU0_SB_CA<6>")
	)
	(segment
		(start 313.556396 -247.63222)
		(end 312.403236 -247.63222)
		(width 0.18288)
		(layer "In2.Cu")
		(net "M_B_CPU0_SB_CA<6>")
	)
	(segment
		(start 320.028062 -248.649236)
		(end 320.028062 -248.119392)
		(width 0.18288)
		(layer "In2.Cu")
		(net "M_B_CPU0_SB_CA<6>")
	)
	(segment
		(start 295.485566 -248.954798)
		(end 295.485566 -247.659652)
		(width 0.18288)
		(layer "In2.Cu")
		(net "M_B_CPU0_SB_CA<6>")
	)
	(segment
		(start 311.612788 -247.92051)
		(end 311.388252 -247.695974)
		(width 0.18288)
		(layer "In2.Cu")
		(net "M_B_CPU0_SB_CA<6>")
	)
	(segment
		(start 300.308264 -247.68302)
		(end 299.827442 -247.68302)
		(width 0.18288)
		(layer "In2.Cu")
		(net "M_B_CPU0_SB_CA<6>")
	)
	(segment
		(start 331.080618 -246.910606)
		(end 322.559426 -246.910606)
		(width 0.18288)
		(layer "In2.Cu")
		(net "M_B_CPU0_SB_CA<6>")
	)
	(segment
		(start 321.54368 -247.926352)
		(end 320.927222 -247.926352)
		(width 0.18288)
		(layer "In2.Cu")
		(net "M_B_CPU0_SB_CA<6>")
	)
	(segment
		(start 320.028062 -248.119392)
		(end 319.835022 -247.926352)
		(width 0.18288)
		(layer "In2.Cu")
		(net "M_B_CPU0_SB_CA<6>")
	)
	(segment
		(start 311.388252 -247.695974)
		(end 309.963058 -247.695974)
		(width 0.18288)
		(layer "In2.Cu")
		(net "M_B_CPU0_SB_CA<6>")
	)
	(segment
		(start 336.085434 -247.178322)
		(end 335.589626 -246.929148)
		(width 0.088646)
		(layer "In2.Cu")
		(net "M_B_CPU0_SB_CA<6>")
	)
	(segment
		(start 309.778146 -247.880886)
		(end 308.068472 -247.880886)
		(width 0.18288)
		(layer "In2.Cu")
		(net "M_B_CPU0_SB_CA<6>")
	)
	(segment
		(start 296.453814 -247.919494)
		(end 296.293794 -248.079514)
		(width 0.18288)
		(layer "In2.Cu")
		(net "M_B_CPU0_SB_CA<6>")
	)
	(segment
		(start 297.18127 -247.919494)
		(end 296.453814 -247.919494)
		(width 0.18288)
		(layer "In2.Cu")
		(net "M_B_CPU0_SB_CA<6>")
	)
	(segment
		(start 320.927222 -247.926352)
		(end 320.734182 -248.119392)
		(width 0.18288)
		(layer "In2.Cu")
		(net "M_B_CPU0_SB_CA<6>")
	)
	(segment
		(start 312.403236 -247.63222)
		(end 312.114946 -247.92051)
		(width 0.18288)
		(layer "In2.Cu")
		(net "M_B_CPU0_SB_CA<6>")
	)
	(segment
		(start 300.560232 -247.934988)
		(end 300.308264 -247.68302)
		(width 0.18288)
		(layer "In2.Cu")
		(net "M_B_CPU0_SB_CA<6>")
	)
	(segment
		(start 331.329792 -246.910606)
		(end 331.080618 -246.910606)
		(width 0.088646)
		(layer "In2.Cu")
		(net "M_B_CPU0_SB_CA<6>")
	)
	(segment
		(start 303.150016 -247.586754)
		(end 302.490378 -247.586754)
		(width 0.18288)
		(layer "In2.Cu")
		(net "M_B_CPU0_SB_CA<6>")
	)
	(segment
		(start 320.541142 -248.842276)
		(end 320.221102 -248.842276)
		(width 0.18288)
		(layer "In2.Cu")
		(net "M_B_CPU0_SB_CA<6>")
	)
	(arc
		(start 333.453232 -246.853964)
		(mid 333.266034 -246.803821)
		(end 333.078836 -246.853964)
		(width 0.088646)
		(layer "In2.Cu")
		(net "M_B_CPU0_SB_CA<6>")
	)
	(arc
		(start 334.018636 -246.853964)
		(mid 333.735934 -246.92974)
		(end 333.453232 -246.853964)
		(width 0.088646)
		(layer "In2.Cu")
		(net "M_B_CPU0_SB_CA<6>")
	)
	(arc
		(start 332.513432 -246.853964)
		(mid 332.326234 -246.803821)
		(end 332.139036 -246.853964)
		(width 0.088646)
		(layer "In2.Cu")
		(net "M_B_CPU0_SB_CA<6>")
	)
	(arc
		(start 335.589626 -246.929148)
		(mid 335.456716 -246.906971)
		(end 335.332832 -246.853964)
		(width 0.088646)
		(layer "In2.Cu")
		(net "M_B_CPU0_SB_CA<6>")
	)
	(arc
		(start 334.393032 -246.853964)
		(mid 334.205834 -246.803821)
		(end 334.018636 -246.853964)
		(width 0.088646)
		(layer "In2.Cu")
		(net "M_B_CPU0_SB_CA<6>")
	)
	(arc
		(start 335.332832 -246.853964)
		(mid 335.145634 -246.803821)
		(end 334.958436 -246.853964)
		(width 0.088646)
		(layer "In2.Cu")
		(net "M_B_CPU0_SB_CA<6>")
	)
	(arc
		(start 333.078836 -246.853964)
		(mid 332.796134 -246.92974)
		(end 332.513432 -246.853964)
		(width 0.088646)
		(layer "In2.Cu")
		(net "M_B_CPU0_SB_CA<6>")
	)
	(arc
		(start 332.139036 -246.853964)
		(mid 332.002667 -246.910406)
		(end 331.856334 -246.929656)
		(width 0.088646)
		(layer "In2.Cu")
		(net "M_B_CPU0_SB_CA<6>")
	)
	(arc
		(start 334.958436 -246.853964)
		(mid 334.675734 -246.92974)
		(end 334.393032 -246.853964)
		(width 0.088646)
		(layer "In2.Cu")
		(net "M_B_CPU0_SB_CA<6>")
	)
	(segment
		(start 292.05301 -248.31675)
		(end 290.355782 -248.31675)
		(width 0.20066)
		(layer "F.Cu")
		(net "M_B_CPU0_SB_CA<5>")
	)
	(segment
		(start 292.321488 -248.755916)
		(end 292.178994 -248.613422)
		(width 0.20066)
		(layer "F.Cu")
		(net "M_B_CPU0_SB_CA<5>")
	)
	(segment
		(start 297.899582 -248.31675)
		(end 297.08348 -248.31675)
		(width 0.20066)
		(layer "F.Cu")
		(net "M_B_CPU0_SB_CA<5>")
	)
	(segment
		(start 292.689534 -248.741692)
		(end 292.67531 -248.755916)
		(width 0.101854)
		(layer "F.Cu")
		(net "M_B_CPU0_SB_CA<5>")
	)
	(segment
		(start 338.43468 -248.527824)
		(end 338.43468 -247.992138)
		(width 0.20066)
		(layer "F.Cu")
		(net "M_B_CPU0_SB_CA<5>")
	)
	(segment
		(start 296.217594 -248.312432)
		(end 295.82237 -248.312432)
		(width 0.20066)
		(layer "F.Cu")
		(net "M_B_CPU0_SB_CA<5>")
	)
	(segment
		(start 295.000426 -248.741692)
		(end 292.927532 -248.741692)
		(width 0.1016)
		(layer "F.Cu")
		(net "M_B_CPU0_SB_CA<5>")
	)
	(segment
		(start 292.178994 -248.613422)
		(end 292.178994 -248.442734)
		(width 0.20066)
		(layer "F.Cu")
		(net "M_B_CPU0_SB_CA<5>")
	)
	(segment
		(start 292.178994 -248.442734)
		(end 292.05301 -248.31675)
		(width 0.20066)
		(layer "F.Cu")
		(net "M_B_CPU0_SB_CA<5>")
	)
	(segment
		(start 299.004482 -248.31675)
		(end 297.899582 -248.31675)
		(width 0.20066)
		(layer "F.Cu")
		(net "M_B_CPU0_SB_CA<5>")
	)
	(segment
		(start 295.693846 -248.592594)
		(end 295.544748 -248.741692)
		(width 0.20066)
		(layer "F.Cu")
		(net "M_B_CPU0_SB_CA<5>")
	)
	(segment
		(start 295.693846 -248.440956)
		(end 295.693846 -248.592594)
		(width 0.20066)
		(layer "F.Cu")
		(net "M_B_CPU0_SB_CA<5>")
	)
	(segment
		(start 338.434934 -248.528078)
		(end 338.43468 -248.527824)
		(width 0.20066)
		(layer "F.Cu")
		(net "M_B_CPU0_SB_CA<5>")
	)
	(segment
		(start 295.544748 -248.741692)
		(end 295.000426 -248.741692)
		(width 0.20066)
		(layer "F.Cu")
		(net "M_B_CPU0_SB_CA<5>")
	)
	(segment
		(start 297.08348 -248.31675)
		(end 296.875962 -248.524268)
		(width 0.20066)
		(layer "F.Cu")
		(net "M_B_CPU0_SB_CA<5>")
	)
	(segment
		(start 296.875962 -248.524268)
		(end 296.42943 -248.524268)
		(width 0.20066)
		(layer "F.Cu")
		(net "M_B_CPU0_SB_CA<5>")
	)
	(segment
		(start 292.927532 -248.741692)
		(end 292.689534 -248.741692)
		(width 0.101854)
		(layer "F.Cu")
		(net "M_B_CPU0_SB_CA<5>")
	)
	(segment
		(start 292.67531 -248.755916)
		(end 292.321488 -248.755916)
		(width 0.20066)
		(layer "F.Cu")
		(net "M_B_CPU0_SB_CA<5>")
	)
	(segment
		(start 296.42943 -248.524268)
		(end 296.217594 -248.312432)
		(width 0.20066)
		(layer "F.Cu")
		(net "M_B_CPU0_SB_CA<5>")
	)
	(segment
		(start 295.82237 -248.312432)
		(end 295.693846 -248.440956)
		(width 0.20066)
		(layer "F.Cu")
		(net "M_B_CPU0_SB_CA<5>")
	)
	(segment
		(start 319.50025 -248.661936)
		(end 319.30721 -248.468896)
		(width 0.18288)
		(layer "In2.Cu")
		(net "M_B_CPU0_SB_CA<5>")
	)
	(segment
		(start 319.50025 -249.193812)
		(end 319.50025 -248.661936)
		(width 0.18288)
		(layer "In2.Cu")
		(net "M_B_CPU0_SB_CA<5>")
	)
	(segment
		(start 311.478168 -248.711212)
		(end 311.285128 -248.518172)
		(width 0.18288)
		(layer "In2.Cu")
		(net "M_B_CPU0_SB_CA<5>")
	)
	(segment
		(start 303.508918 -248.468642)
		(end 302.951134 -249.026426)
		(width 0.18288)
		(layer "In2.Cu")
		(net "M_B_CPU0_SB_CA<5>")
	)
	(segment
		(start 318.08801 -249.193812)
		(end 318.08801 -248.661936)
		(width 0.18288)
		(layer "In2.Cu")
		(net "M_B_CPU0_SB_CA<5>")
	)
	(segment
		(start 312.36666 -249.005344)
		(end 312.072528 -248.711212)
		(width 0.18288)
		(layer "In2.Cu")
		(net "M_B_CPU0_SB_CA<5>")
	)
	(segment
		(start 313.612276 -249.005344)
		(end 312.36666 -249.005344)
		(width 0.18288)
		(layer "In2.Cu")
		(net "M_B_CPU0_SB_CA<5>")
	)
	(segment
		(start 318.08801 -248.661936)
		(end 317.89497 -248.468896)
		(width 0.18288)
		(layer "In2.Cu")
		(net "M_B_CPU0_SB_CA<5>")
	)
	(segment
		(start 316.639956 -248.62917)
		(end 316.446916 -248.43613)
		(width 0.18288)
		(layer "In2.Cu")
		(net "M_B_CPU0_SB_CA<5>")
	)
	(segment
		(start 318.79413 -248.661936)
		(end 318.79413 -249.193812)
		(width 0.18288)
		(layer "In2.Cu")
		(net "M_B_CPU0_SB_CA<5>")
	)
	(segment
		(start 336.837782 -247.50268)
		(end 336.827368 -247.496584)
		(width 0.088646)
		(layer "In2.Cu")
		(net "M_B_CPU0_SB_CA<5>")
	)
	(segment
		(start 312.072528 -248.711212)
		(end 311.478168 -248.711212)
		(width 0.18288)
		(layer "In2.Cu")
		(net "M_B_CPU0_SB_CA<5>")
	)
	(segment
		(start 305.923442 -249.101864)
		(end 304.921158 -249.101864)
		(width 0.18288)
		(layer "In2.Cu")
		(net "M_B_CPU0_SB_CA<5>")
	)
	(segment
		(start 304.921158 -249.101864)
		(end 304.287936 -248.468642)
		(width 0.18288)
		(layer "In2.Cu")
		(net "M_B_CPU0_SB_CA<5>")
	)
	(segment
		(start 335.3435 -247.496584)
		(end 335.341468 -247.497854)
		(width 0.088646)
		(layer "In2.Cu")
		(net "M_B_CPU0_SB_CA<5>")
	)
	(segment
		(start 301.893986 -248.453402)
		(end 300.720252 -248.453402)
		(width 0.18288)
		(layer "In2.Cu")
		(net "M_B_CPU0_SB_CA<5>")
	)
	(segment
		(start 308.398672 -248.44375)
		(end 307.796184 -249.046238)
		(width 0.18288)
		(layer "In2.Cu")
		(net "M_B_CPU0_SB_CA<5>")
	)
	(segment
		(start 338.43468 -247.992138)
		(end 337.918298 -247.603264)
		(width 0.088646)
		(layer "In2.Cu")
		(net "M_B_CPU0_SB_CA<5>")
	)
	(segment
		(start 299.21073 -248.592086)
		(end 299.004482 -248.385838)
		(width 0.18288)
		(layer "In2.Cu")
		(net "M_B_CPU0_SB_CA<5>")
	)
	(segment
		(start 306.512976 -248.51233)
		(end 305.923442 -249.101864)
		(width 0.18288)
		(layer "In2.Cu")
		(net "M_B_CPU0_SB_CA<5>")
	)
	(segment
		(start 335.341468 -247.497854)
		(end 335.332832 -247.50268)
		(width 0.088646)
		(layer "In2.Cu")
		(net "M_B_CPU0_SB_CA<5>")
	)
	(segment
		(start 310.261762 -248.956576)
		(end 309.988458 -248.956576)
		(width 0.18288)
		(layer "In2.Cu")
		(net "M_B_CPU0_SB_CA<5>")
	)
	(segment
		(start 316.446916 -248.43613)
		(end 314.18149 -248.43613)
		(width 0.18288)
		(layer "In2.Cu")
		(net "M_B_CPU0_SB_CA<5>")
	)
	(segment
		(start 307.37429 -249.046238)
		(end 307.18125 -248.853198)
		(width 0.18288)
		(layer "In2.Cu")
		(net "M_B_CPU0_SB_CA<5>")
	)
	(segment
		(start 314.18149 -248.43613)
		(end 313.612276 -249.005344)
		(width 0.18288)
		(layer "In2.Cu")
		(net "M_B_CPU0_SB_CA<5>")
	)
	(segment
		(start 329.82535 -247.70588)
		(end 329.375516 -247.256046)
		(width 0.18288)
		(layer "In2.Cu")
		(net "M_B_CPU0_SB_CA<5>")
	)
	(segment
		(start 302.951134 -249.026426)
		(end 302.46701 -249.026426)
		(width 0.18288)
		(layer "In2.Cu")
		(net "M_B_CPU0_SB_CA<5>")
	)
	(segment
		(start 302.46701 -249.026426)
		(end 301.893986 -248.453402)
		(width 0.18288)
		(layer "In2.Cu")
		(net "M_B_CPU0_SB_CA<5>")
	)
	(segment
		(start 317.57493 -248.468896)
		(end 317.38189 -248.661936)
		(width 0.18288)
		(layer "In2.Cu")
		(net "M_B_CPU0_SB_CA<5>")
	)
	(segment
		(start 307.18125 -248.853198)
		(end 307.18125 -248.633234)
		(width 0.18288)
		(layer "In2.Cu")
		(net "M_B_CPU0_SB_CA<5>")
	)
	(segment
		(start 332.396338 -247.592342)
		(end 332.2828 -247.70588)
		(width 0.088646)
		(layer "In2.Cu")
		(net "M_B_CPU0_SB_CA<5>")
	)
	(segment
		(start 318.60109 -249.386852)
		(end 318.28105 -249.386852)
		(width 0.18288)
		(layer "In2.Cu")
		(net "M_B_CPU0_SB_CA<5>")
	)
	(segment
		(start 299.21073 -248.724674)
		(end 299.21073 -248.592086)
		(width 0.18288)
		(layer "In2.Cu")
		(net "M_B_CPU0_SB_CA<5>")
	)
	(segment
		(start 319.69329 -249.386852)
		(end 319.50025 -249.193812)
		(width 0.18288)
		(layer "In2.Cu")
		(net "M_B_CPU0_SB_CA<5>")
	)
	(segment
		(start 317.18885 -249.386852)
		(end 316.776608 -249.386852)
		(width 0.18288)
		(layer "In2.Cu")
		(net "M_B_CPU0_SB_CA<5>")
	)
	(segment
		(start 311.092088 -248.207784)
		(end 310.640222 -248.207784)
		(width 0.18288)
		(layer "In2.Cu")
		(net "M_B_CPU0_SB_CA<5>")
	)
	(segment
		(start 316.776608 -249.386852)
		(end 316.639956 -249.2502)
		(width 0.18288)
		(layer "In2.Cu")
		(net "M_B_CPU0_SB_CA<5>")
	)
	(segment
		(start 318.98717 -248.468896)
		(end 318.79413 -248.661936)
		(width 0.18288)
		(layer "In2.Cu")
		(net "M_B_CPU0_SB_CA<5>")
	)
	(segment
		(start 309.988458 -248.956576)
		(end 309.475632 -248.44375)
		(width 0.18288)
		(layer "In2.Cu")
		(net "M_B_CPU0_SB_CA<5>")
	)
	(segment
		(start 319.30721 -248.468896)
		(end 318.98717 -248.468896)
		(width 0.18288)
		(layer "In2.Cu")
		(net "M_B_CPU0_SB_CA<5>")
	)
	(segment
		(start 304.287936 -248.468642)
		(end 303.508918 -248.468642)
		(width 0.18288)
		(layer "In2.Cu")
		(net "M_B_CPU0_SB_CA<5>")
	)
	(segment
		(start 311.285128 -248.400824)
		(end 311.092088 -248.207784)
		(width 0.18288)
		(layer "In2.Cu")
		(net "M_B_CPU0_SB_CA<5>")
	)
	(segment
		(start 310.454802 -248.393204)
		(end 310.454802 -248.763536)
		(width 0.18288)
		(layer "In2.Cu")
		(net "M_B_CPU0_SB_CA<5>")
	)
	(segment
		(start 307.060346 -248.51233)
		(end 306.512976 -248.51233)
		(width 0.18288)
		(layer "In2.Cu")
		(net "M_B_CPU0_SB_CA<5>")
	)
	(segment
		(start 311.285128 -248.518172)
		(end 311.285128 -248.400824)
		(width 0.18288)
		(layer "In2.Cu")
		(net "M_B_CPU0_SB_CA<5>")
	)
	(segment
		(start 309.475632 -248.44375)
		(end 308.398672 -248.44375)
		(width 0.18288)
		(layer "In2.Cu")
		(net "M_B_CPU0_SB_CA<5>")
	)
	(segment
		(start 307.18125 -248.633234)
		(end 307.060346 -248.51233)
		(width 0.18288)
		(layer "In2.Cu")
		(net "M_B_CPU0_SB_CA<5>")
	)
	(segment
		(start 317.38189 -248.661936)
		(end 317.38189 -249.193812)
		(width 0.18288)
		(layer "In2.Cu")
		(net "M_B_CPU0_SB_CA<5>")
	)
	(segment
		(start 329.375516 -247.256046)
		(end 322.93306 -247.256046)
		(width 0.18288)
		(layer "In2.Cu")
		(net "M_B_CPU0_SB_CA<5>")
	)
	(segment
		(start 331.715618 -247.70588)
		(end 329.82535 -247.70588)
		(width 0.18288)
		(layer "In2.Cu")
		(net "M_B_CPU0_SB_CA<5>")
	)
	(segment
		(start 317.38189 -249.193812)
		(end 317.18885 -249.386852)
		(width 0.18288)
		(layer "In2.Cu")
		(net "M_B_CPU0_SB_CA<5>")
	)
	(segment
		(start 320.802254 -249.386852)
		(end 319.69329 -249.386852)
		(width 0.18288)
		(layer "In2.Cu")
		(net "M_B_CPU0_SB_CA<5>")
	)
	(segment
		(start 300.720252 -248.453402)
		(end 300.119796 -249.053858)
		(width 0.18288)
		(layer "In2.Cu")
		(net "M_B_CPU0_SB_CA<5>")
	)
	(segment
		(start 316.639956 -249.2502)
		(end 316.639956 -248.62917)
		(width 0.18288)
		(layer "In2.Cu")
		(net "M_B_CPU0_SB_CA<5>")
	)
	(segment
		(start 307.796184 -249.046238)
		(end 307.37429 -249.046238)
		(width 0.18288)
		(layer "In2.Cu")
		(net "M_B_CPU0_SB_CA<5>")
	)
	(segment
		(start 299.004482 -248.385838)
		(end 299.004482 -248.31675)
		(width 0.18288)
		(layer "In2.Cu")
		(net "M_B_CPU0_SB_CA<5>")
	)
	(segment
		(start 332.2828 -247.70588)
		(end 331.715618 -247.70588)
		(width 0.088646)
		(layer "In2.Cu")
		(net "M_B_CPU0_SB_CA<5>")
	)
	(segment
		(start 317.89497 -248.468896)
		(end 317.57493 -248.468896)
		(width 0.18288)
		(layer "In2.Cu")
		(net "M_B_CPU0_SB_CA<5>")
	)
	(segment
		(start 318.28105 -249.386852)
		(end 318.08801 -249.193812)
		(width 0.18288)
		(layer "In2.Cu")
		(net "M_B_CPU0_SB_CA<5>")
	)
	(segment
		(start 318.79413 -249.193812)
		(end 318.60109 -249.386852)
		(width 0.18288)
		(layer "In2.Cu")
		(net "M_B_CPU0_SB_CA<5>")
	)
	(segment
		(start 310.454802 -248.763536)
		(end 310.261762 -248.956576)
		(width 0.18288)
		(layer "In2.Cu")
		(net "M_B_CPU0_SB_CA<5>")
	)
	(segment
		(start 310.640222 -248.207784)
		(end 310.454802 -248.393204)
		(width 0.18288)
		(layer "In2.Cu")
		(net "M_B_CPU0_SB_CA<5>")
	)
	(segment
		(start 322.93306 -247.256046)
		(end 320.802254 -249.386852)
		(width 0.18288)
		(layer "In2.Cu")
		(net "M_B_CPU0_SB_CA<5>")
	)
	(segment
		(start 299.539914 -249.053858)
		(end 299.21073 -248.724674)
		(width 0.18288)
		(layer "In2.Cu")
		(net "M_B_CPU0_SB_CA<5>")
	)
	(segment
		(start 300.119796 -249.053858)
		(end 299.539914 -249.053858)
		(width 0.18288)
		(layer "In2.Cu")
		(net "M_B_CPU0_SB_CA<5>")
	)
	(arc
		(start 334.393032 -247.50268)
		(mid 334.205834 -247.552823)
		(end 334.018636 -247.50268)
		(width 0.088646)
		(layer "In2.Cu")
		(net "M_B_CPU0_SB_CA<5>")
	)
	(arc
		(start 332.513432 -247.50268)
		(mid 332.451954 -247.543682)
		(end 332.396338 -247.592342)
		(width 0.088646)
		(layer "In2.Cu")
		(net "M_B_CPU0_SB_CA<5>")
	)
	(arc
		(start 337.302094 -247.553226)
		(mid 337.064532 -247.577586)
		(end 336.837782 -247.50268)
		(width 0.088646)
		(layer "In2.Cu")
		(net "M_B_CPU0_SB_CA<5>")
	)
	(arc
		(start 333.078836 -247.50268)
		(mid 332.796134 -247.426904)
		(end 332.513432 -247.50268)
		(width 0.088646)
		(layer "In2.Cu")
		(net "M_B_CPU0_SB_CA<5>")
	)
	(arc
		(start 333.453232 -247.50268)
		(mid 333.266034 -247.552823)
		(end 333.078836 -247.50268)
		(width 0.088646)
		(layer "In2.Cu")
		(net "M_B_CPU0_SB_CA<5>")
	)
	(arc
		(start 336.827368 -247.496584)
		(mid 336.54919 -247.426861)
		(end 336.272632 -247.50268)
		(width 0.088646)
		(layer "In2.Cu")
		(net "M_B_CPU0_SB_CA<5>")
	)
	(arc
		(start 337.918298 -247.603264)
		(mid 337.615188 -247.516794)
		(end 337.302094 -247.553226)
		(width 0.088646)
		(layer "In2.Cu")
		(net "M_B_CPU0_SB_CA<5>")
	)
	(arc
		(start 334.018636 -247.50268)
		(mid 333.735934 -247.426904)
		(end 333.453232 -247.50268)
		(width 0.088646)
		(layer "In2.Cu")
		(net "M_B_CPU0_SB_CA<5>")
	)
	(arc
		(start 334.958436 -247.50268)
		(mid 334.675734 -247.426904)
		(end 334.393032 -247.50268)
		(width 0.088646)
		(layer "In2.Cu")
		(net "M_B_CPU0_SB_CA<5>")
	)
	(arc
		(start 335.332832 -247.50268)
		(mid 335.145634 -247.552823)
		(end 334.958436 -247.50268)
		(width 0.088646)
		(layer "In2.Cu")
		(net "M_B_CPU0_SB_CA<5>")
	)
	(arc
		(start 335.898236 -247.50268)
		(mid 335.621677 -247.426937)
		(end 335.3435 -247.496584)
		(width 0.088646)
		(layer "In2.Cu")
		(net "M_B_CPU0_SB_CA<5>")
	)
	(arc
		(start 336.272632 -247.50268)
		(mid 336.085434 -247.552823)
		(end 335.898236 -247.50268)
		(width 0.088646)
		(layer "In2.Cu")
		(net "M_B_CPU0_SB_CA<5>")
	)
	(segment
		(start 291.225986 -248.741692)
		(end 289.240468 -248.741692)
		(width 0.1016)
		(layer "F.Cu")
		(net "M_B_CPU0_SB_CA<4>")
	)
	(segment
		(start 336.55508 -248.527824)
		(end 336.55508 -247.992138)
		(width 0.20066)
		(layer "F.Cu")
		(net "M_B_CPU0_SB_CA<4>")
	)
	(segment
		(start 287.589976 -249.166634)
		(end 286.255714 -249.166634)
		(width 0.20066)
		(layer "F.Cu")
		(net "M_B_CPU0_SB_CA<4>")
	)
	(segment
		(start 291.735256 -248.741692)
		(end 291.556694 -248.741692)
		(width 0.20066)
		(layer "F.Cu")
		(net "M_B_CPU0_SB_CA<4>")
	)
	(segment
		(start 291.556694 -248.741692)
		(end 291.225986 -248.741692)
		(width 0.101854)
		(layer "F.Cu")
		(net "M_B_CPU0_SB_CA<4>")
	)
	(segment
		(start 293.799514 -249.166634)
		(end 292.160198 -249.166634)
		(width 0.20066)
		(layer "F.Cu")
		(net "M_B_CPU0_SB_CA<4>")
	)
	(segment
		(start 287.801304 -249.377962)
		(end 287.589976 -249.166634)
		(width 0.20066)
		(layer "F.Cu")
		(net "M_B_CPU0_SB_CA<4>")
	)
	(segment
		(start 289.240468 -248.741692)
		(end 289.231578 -248.732802)
		(width 0.1016)
		(layer "F.Cu")
		(net "M_B_CPU0_SB_CA<4>")
	)
	(segment
		(start 288.62274 -248.732802)
		(end 288.46018 -248.895362)
		(width 0.20066)
		(layer "F.Cu")
		(net "M_B_CPU0_SB_CA<4>")
	)
	(segment
		(start 288.305748 -249.377962)
		(end 287.801304 -249.377962)
		(width 0.20066)
		(layer "F.Cu")
		(net "M_B_CPU0_SB_CA<4>")
	)
	(segment
		(start 289.231578 -248.732802)
		(end 288.62274 -248.732802)
		(width 0.20066)
		(layer "F.Cu")
		(net "M_B_CPU0_SB_CA<4>")
	)
	(segment
		(start 292.160198 -249.166634)
		(end 291.735256 -248.741692)
		(width 0.20066)
		(layer "F.Cu")
		(net "M_B_CPU0_SB_CA<4>")
	)
	(segment
		(start 294.904414 -249.166634)
		(end 293.799514 -249.166634)
		(width 0.20066)
		(layer "F.Cu")
		(net "M_B_CPU0_SB_CA<4>")
	)
	(segment
		(start 336.555334 -248.528078)
		(end 336.55508 -248.527824)
		(width 0.20066)
		(layer "F.Cu")
		(net "M_B_CPU0_SB_CA<4>")
	)
	(segment
		(start 288.46018 -249.22353)
		(end 288.305748 -249.377962)
		(width 0.20066)
		(layer "F.Cu")
		(net "M_B_CPU0_SB_CA<4>")
	)
	(segment
		(start 288.46018 -248.895362)
		(end 288.46018 -249.22353)
		(width 0.20066)
		(layer "F.Cu")
		(net "M_B_CPU0_SB_CA<4>")
	)
	(segment
		(start 313.924188 -249.675904)
		(end 313.774836 -249.526552)
		(width 0.18288)
		(layer "In2.Cu")
		(net "M_B_CPU0_SB_CA<4>")
	)
	(segment
		(start 321.010534 -249.897392)
		(end 316.353444 -249.897392)
		(width 0.18288)
		(layer "In2.Cu")
		(net "M_B_CPU0_SB_CA<4>")
	)
	(segment
		(start 307.54193 -249.579892)
		(end 307.48986 -249.631962)
		(width 0.18288)
		(layer "In2.Cu")
		(net "M_B_CPU0_SB_CA<4>")
	)
	(segment
		(start 295.42105 -249.68327)
		(end 294.904414 -249.166634)
		(width 0.18288)
		(layer "In2.Cu")
		(net "M_B_CPU0_SB_CA<4>")
	)
	(segment
		(start 335.831688 -247.684798)
		(end 335.802732 -247.66778)
		(width 0.088646)
		(layer "In2.Cu")
		(net "M_B_CPU0_SB_CA<4>")
	)
	(segment
		(start 295.42105 -250.444)
		(end 295.42105 -249.68327)
		(width 0.18288)
		(layer "In2.Cu")
		(net "M_B_CPU0_SB_CA<4>")
	)
	(segment
		(start 314.900056 -248.97334)
		(end 314.197492 -249.675904)
		(width 0.18288)
		(layer "In2.Cu")
		(net "M_B_CPU0_SB_CA<4>")
	)
	(segment
		(start 296.418254 -249.61215)
		(end 296.209212 -249.821192)
		(width 0.18288)
		(layer "In2.Cu")
		(net "M_B_CPU0_SB_CA<4>")
	)
	(segment
		(start 300.019974 -249.585988)
		(end 299.845222 -249.76074)
		(width 0.18288)
		(layer "In2.Cu")
		(net "M_B_CPU0_SB_CA<4>")
	)
	(segment
		(start 297.546776 -248.756932)
		(end 297.353482 -248.950226)
		(width 0.18288)
		(layer "In2.Cu")
		(net "M_B_CPU0_SB_CA<4>")
	)
	(segment
		(start 315.822584 -248.97334)
		(end 314.900056 -248.97334)
		(width 0.18288)
		(layer "In2.Cu")
		(net "M_B_CPU0_SB_CA<4>")
	)
	(segment
		(start 314.197492 -249.675904)
		(end 313.924188 -249.675904)
		(width 0.18288)
		(layer "In2.Cu")
		(net "M_B_CPU0_SB_CA<4>")
	)
	(segment
		(start 297.353482 -249.501152)
		(end 297.242484 -249.61215)
		(width 0.18288)
		(layer "In2.Cu")
		(net "M_B_CPU0_SB_CA<4>")
	)
	(segment
		(start 299.290486 -249.591576)
		(end 298.334176 -249.591576)
		(width 0.18288)
		(layer "In2.Cu")
		(net "M_B_CPU0_SB_CA<4>")
	)
	(segment
		(start 323.30644 -247.601486)
		(end 321.010534 -249.897392)
		(width 0.18288)
		(layer "In2.Cu")
		(net "M_B_CPU0_SB_CA<4>")
	)
	(segment
		(start 332.530958 -247.726962)
		(end 332.530958 -247.727216)
		(width 0.088646)
		(layer "In2.Cu")
		(net "M_B_CPU0_SB_CA<4>")
	)
	(segment
		(start 332.530958 -247.727216)
		(end 332.204822 -248.053352)
		(width 0.088646)
		(layer "In2.Cu")
		(net "M_B_CPU0_SB_CA<4>")
	)
	(segment
		(start 329.30211 -248.053352)
		(end 328.850244 -247.601486)
		(width 0.18288)
		(layer "In2.Cu")
		(net "M_B_CPU0_SB_CA<4>")
	)
	(segment
		(start 328.850244 -247.601486)
		(end 323.30644 -247.601486)
		(width 0.18288)
		(layer "In2.Cu")
		(net "M_B_CPU0_SB_CA<4>")
	)
	(segment
		(start 298.334176 -249.591576)
		(end 298.168568 -249.425968)
		(width 0.18288)
		(layer "In2.Cu")
		(net "M_B_CPU0_SB_CA<4>")
	)
	(segment
		(start 331.715618 -248.053352)
		(end 329.30211 -248.053352)
		(width 0.18288)
		(layer "In2.Cu")
		(net "M_B_CPU0_SB_CA<4>")
	)
	(segment
		(start 316.353444 -249.897392)
		(end 316.089792 -249.63374)
		(width 0.18288)
		(layer "In2.Cu")
		(net "M_B_CPU0_SB_CA<4>")
	)
	(segment
		(start 295.561004 -250.583954)
		(end 295.42105 -250.444)
		(width 0.18288)
		(layer "In2.Cu")
		(net "M_B_CPU0_SB_CA<4>")
	)
	(segment
		(start 299.45965 -249.76074)
		(end 299.290486 -249.591576)
		(width 0.18288)
		(layer "In2.Cu")
		(net "M_B_CPU0_SB_CA<4>")
	)
	(segment
		(start 302.800766 -249.585988)
		(end 300.019974 -249.585988)
		(width 0.18288)
		(layer "In2.Cu")
		(net "M_B_CPU0_SB_CA<4>")
	)
	(segment
		(start 298.168568 -249.425968)
		(end 298.168568 -248.916952)
		(width 0.18288)
		(layer "In2.Cu")
		(net "M_B_CPU0_SB_CA<4>")
	)
	(segment
		(start 311.60085 -249.661172)
		(end 311.32145 -249.381772)
		(width 0.18288)
		(layer "In2.Cu")
		(net "M_B_CPU0_SB_CA<4>")
	)
	(segment
		(start 296.049192 -250.583954)
		(end 295.561004 -250.583954)
		(width 0.18288)
		(layer "In2.Cu")
		(net "M_B_CPU0_SB_CA<4>")
	)
	(segment
		(start 313.774836 -249.526552)
		(end 312.132726 -249.526552)
		(width 0.18288)
		(layer "In2.Cu")
		(net "M_B_CPU0_SB_CA<4>")
	)
	(segment
		(start 311.32145 -249.381772)
		(end 310.83885 -249.381772)
		(width 0.18288)
		(layer "In2.Cu")
		(net "M_B_CPU0_SB_CA<4>")
	)
	(segment
		(start 332.204822 -248.053352)
		(end 331.715618 -248.053352)
		(width 0.088646)
		(layer "In2.Cu")
		(net "M_B_CPU0_SB_CA<4>")
	)
	(segment
		(start 298.008548 -248.756932)
		(end 297.546776 -248.756932)
		(width 0.18288)
		(layer "In2.Cu")
		(net "M_B_CPU0_SB_CA<4>")
	)
	(segment
		(start 311.998106 -249.661172)
		(end 311.60085 -249.661172)
		(width 0.18288)
		(layer "In2.Cu")
		(net "M_B_CPU0_SB_CA<4>")
	)
	(segment
		(start 302.84674 -249.631962)
		(end 302.800766 -249.585988)
		(width 0.18288)
		(layer "In2.Cu")
		(net "M_B_CPU0_SB_CA<4>")
	)
	(segment
		(start 296.209212 -249.821192)
		(end 296.209212 -250.423934)
		(width 0.18288)
		(layer "In2.Cu")
		(net "M_B_CPU0_SB_CA<4>")
	)
	(segment
		(start 316.089792 -249.63374)
		(end 316.089792 -249.240548)
		(width 0.18288)
		(layer "In2.Cu")
		(net "M_B_CPU0_SB_CA<4>")
	)
	(segment
		(start 297.353482 -248.950226)
		(end 297.353482 -249.501152)
		(width 0.18288)
		(layer "In2.Cu")
		(net "M_B_CPU0_SB_CA<4>")
	)
	(segment
		(start 296.209212 -250.423934)
		(end 296.049192 -250.583954)
		(width 0.18288)
		(layer "In2.Cu")
		(net "M_B_CPU0_SB_CA<4>")
	)
	(segment
		(start 310.64073 -249.579892)
		(end 307.54193 -249.579892)
		(width 0.18288)
		(layer "In2.Cu")
		(net "M_B_CPU0_SB_CA<4>")
	)
	(segment
		(start 310.83885 -249.381772)
		(end 310.64073 -249.579892)
		(width 0.18288)
		(layer "In2.Cu")
		(net "M_B_CPU0_SB_CA<4>")
	)
	(segment
		(start 299.845222 -249.76074)
		(end 299.45965 -249.76074)
		(width 0.18288)
		(layer "In2.Cu")
		(net "M_B_CPU0_SB_CA<4>")
	)
	(segment
		(start 307.48986 -249.631962)
		(end 302.84674 -249.631962)
		(width 0.18288)
		(layer "In2.Cu")
		(net "M_B_CPU0_SB_CA<4>")
	)
	(segment
		(start 316.089792 -249.240548)
		(end 315.822584 -248.97334)
		(width 0.18288)
		(layer "In2.Cu")
		(net "M_B_CPU0_SB_CA<4>")
	)
	(segment
		(start 298.168568 -248.916952)
		(end 298.008548 -248.756932)
		(width 0.18288)
		(layer "In2.Cu")
		(net "M_B_CPU0_SB_CA<4>")
	)
	(segment
		(start 312.132726 -249.526552)
		(end 311.998106 -249.661172)
		(width 0.18288)
		(layer "In2.Cu")
		(net "M_B_CPU0_SB_CA<4>")
	)
	(segment
		(start 297.242484 -249.61215)
		(end 296.418254 -249.61215)
		(width 0.18288)
		(layer "In2.Cu")
		(net "M_B_CPU0_SB_CA<4>")
	)
	(segment
		(start 336.55508 -247.992138)
		(end 335.831688 -247.684798)
		(width 0.088646)
		(layer "In2.Cu")
		(net "M_B_CPU0_SB_CA<4>")
	)
	(arc
		(start 332.983332 -247.66778)
		(mid 332.796134 -247.617637)
		(end 332.608936 -247.66778)
		(width 0.088646)
		(layer "In2.Cu")
		(net "M_B_CPU0_SB_CA<4>")
	)
	(arc
		(start 334.862932 -247.66778)
		(mid 334.675734 -247.617637)
		(end 334.488536 -247.66778)
		(width 0.088646)
		(layer "In2.Cu")
		(net "M_B_CPU0_SB_CA<4>")
	)
	(arc
		(start 333.548736 -247.66778)
		(mid 333.266034 -247.743556)
		(end 332.983332 -247.66778)
		(width 0.088646)
		(layer "In2.Cu")
		(net "M_B_CPU0_SB_CA<4>")
	)
	(arc
		(start 333.923132 -247.66778)
		(mid 333.735934 -247.617637)
		(end 333.548736 -247.66778)
		(width 0.088646)
		(layer "In2.Cu")
		(net "M_B_CPU0_SB_CA<4>")
	)
	(arc
		(start 335.802732 -247.66778)
		(mid 335.615534 -247.617603)
		(end 335.428336 -247.66778)
		(width 0.088646)
		(layer "In2.Cu")
		(net "M_B_CPU0_SB_CA<4>")
	)
	(arc
		(start 332.608936 -247.66778)
		(mid 332.568006 -247.694813)
		(end 332.530958 -247.726962)
		(width 0.088646)
		(layer "In2.Cu")
		(net "M_B_CPU0_SB_CA<4>")
	)
	(arc
		(start 335.428336 -247.66778)
		(mid 335.145634 -247.743556)
		(end 334.862932 -247.66778)
		(width 0.088646)
		(layer "In2.Cu")
		(net "M_B_CPU0_SB_CA<4>")
	)
	(arc
		(start 334.488536 -247.66778)
		(mid 334.205834 -247.743556)
		(end 333.923132 -247.66778)
		(width 0.088646)
		(layer "In2.Cu")
		(net "M_B_CPU0_SB_CA<4>")
	)
	(segment
		(start 292.178994 -250.313444)
		(end 292.178994 -250.142756)
		(width 0.20066)
		(layer "F.Cu")
		(net "M_B_CPU0_SB_CA<3>")
	)
	(segment
		(start 292.321488 -250.455938)
		(end 292.178994 -250.313444)
		(width 0.20066)
		(layer "F.Cu")
		(net "M_B_CPU0_SB_CA<3>")
	)
	(segment
		(start 296.217594 -250.012454)
		(end 295.82237 -250.012454)
		(width 0.20066)
		(layer "F.Cu")
		(net "M_B_CPU0_SB_CA<3>")
	)
	(segment
		(start 295.544748 -250.441714)
		(end 295.000426 -250.441714)
		(width 0.20066)
		(layer "F.Cu")
		(net "M_B_CPU0_SB_CA<3>")
	)
	(segment
		(start 295.693846 -250.292616)
		(end 295.544748 -250.441714)
		(width 0.20066)
		(layer "F.Cu")
		(net "M_B_CPU0_SB_CA<3>")
	)
	(segment
		(start 337.96478 -249.342148)
		(end 337.965034 -249.341894)
		(width 0.20066)
		(layer "F.Cu")
		(net "M_B_CPU0_SB_CA<3>")
	)
	(segment
		(start 292.67531 -250.455938)
		(end 292.321488 -250.455938)
		(width 0.20066)
		(layer "F.Cu")
		(net "M_B_CPU0_SB_CA<3>")
	)
	(segment
		(start 295.000426 -250.441714)
		(end 292.927532 -250.441714)
		(width 0.1016)
		(layer "F.Cu")
		(net "M_B_CPU0_SB_CA<3>")
	)
	(segment
		(start 295.693846 -250.140978)
		(end 295.693846 -250.292616)
		(width 0.20066)
		(layer "F.Cu")
		(net "M_B_CPU0_SB_CA<3>")
	)
	(segment
		(start 292.689534 -250.441714)
		(end 292.67531 -250.455938)
		(width 0.101854)
		(layer "F.Cu")
		(net "M_B_CPU0_SB_CA<3>")
	)
	(segment
		(start 292.178994 -250.142756)
		(end 292.05301 -250.016772)
		(width 0.20066)
		(layer "F.Cu")
		(net "M_B_CPU0_SB_CA<3>")
	)
	(segment
		(start 297.08348 -250.016772)
		(end 296.875962 -250.22429)
		(width 0.20066)
		(layer "F.Cu")
		(net "M_B_CPU0_SB_CA<3>")
	)
	(segment
		(start 337.965034 -249.341894)
		(end 337.965034 -248.806208)
		(width 0.20066)
		(layer "F.Cu")
		(net "M_B_CPU0_SB_CA<3>")
	)
	(segment
		(start 297.899582 -250.016772)
		(end 297.08348 -250.016772)
		(width 0.20066)
		(layer "F.Cu")
		(net "M_B_CPU0_SB_CA<3>")
	)
	(segment
		(start 295.82237 -250.012454)
		(end 295.693846 -250.140978)
		(width 0.20066)
		(layer "F.Cu")
		(net "M_B_CPU0_SB_CA<3>")
	)
	(segment
		(start 292.05301 -250.016772)
		(end 290.355782 -250.016772)
		(width 0.20066)
		(layer "F.Cu")
		(net "M_B_CPU0_SB_CA<3>")
	)
	(segment
		(start 296.42943 -250.22429)
		(end 296.217594 -250.012454)
		(width 0.20066)
		(layer "F.Cu")
		(net "M_B_CPU0_SB_CA<3>")
	)
	(segment
		(start 292.927532 -250.441714)
		(end 292.689534 -250.441714)
		(width 0.101854)
		(layer "F.Cu")
		(net "M_B_CPU0_SB_CA<3>")
	)
	(segment
		(start 299.004482 -250.016772)
		(end 297.899582 -250.016772)
		(width 0.20066)
		(layer "F.Cu")
		(net "M_B_CPU0_SB_CA<3>")
	)
	(segment
		(start 296.875962 -250.22429)
		(end 296.42943 -250.22429)
		(width 0.20066)
		(layer "F.Cu")
		(net "M_B_CPU0_SB_CA<3>")
	)
	(segment
		(start 336.368136 -248.316496)
		(end 336.367882 -248.316496)
		(width 0.088646)
		(layer "In2.Cu")
		(net "M_B_CPU0_SB_CA<3>")
	)
	(segment
		(start 337.307936 -248.31675)
		(end 337.307174 -248.316496)
		(width 0.088646)
		(layer "In2.Cu")
		(net "M_B_CPU0_SB_CA<3>")
	)
	(segment
		(start 319.63741 -251.260356)
		(end 319.63741 -250.603512)
		(width 0.18288)
		(layer "In2.Cu")
		(net "M_B_CPU0_SB_CA<3>")
	)
	(segment
		(start 304.315368 -250.146058)
		(end 303.216564 -250.146058)
		(width 0.18288)
		(layer "In2.Cu")
		(net "M_B_CPU0_SB_CA<3>")
	)
	(segment
		(start 301.897796 -250.10999)
		(end 300.759368 -250.10999)
		(width 0.18288)
		(layer "In2.Cu")
		(net "M_B_CPU0_SB_CA<3>")
	)
	(segment
		(start 320.34353 -251.260356)
		(end 320.15049 -251.453396)
		(width 0.18288)
		(layer "In2.Cu")
		(net "M_B_CPU0_SB_CA<3>")
	)
	(segment
		(start 333.427832 -248.367296)
		(end 332.719172 -249.075956)
		(width 0.088646)
		(layer "In2.Cu")
		(net "M_B_CPU0_SB_CA<3>")
	)
	(segment
		(start 328.44994 -247.946926)
		(end 323.680582 -247.946926)
		(width 0.18288)
		(layer "In2.Cu")
		(net "M_B_CPU0_SB_CA<3>")
	)
	(segment
		(start 306.924964 -250.146566)
		(end 306.572666 -250.146566)
		(width 0.18288)
		(layer "In2.Cu")
		(net "M_B_CPU0_SB_CA<3>")
	)
	(segment
		(start 323.680582 -247.946926)
		(end 321.217036 -250.410472)
		(width 0.18288)
		(layer "In2.Cu")
		(net "M_B_CPU0_SB_CA<3>")
	)
	(segment
		(start 307.953664 -250.455176)
		(end 307.953664 -250.560078)
		(width 0.18288)
		(layer "In2.Cu")
		(net "M_B_CPU0_SB_CA<3>")
	)
	(segment
		(start 315.83757 -250.410472)
		(end 315.575442 -250.148344)
		(width 0.18288)
		(layer "In2.Cu")
		(net "M_B_CPU0_SB_CA<3>")
	)
	(segment
		(start 319.83045 -251.453396)
		(end 319.63741 -251.260356)
		(width 0.18288)
		(layer "In2.Cu")
		(net "M_B_CPU0_SB_CA<3>")
	)
	(segment
		(start 314.596526 -250.410472)
		(end 313.910472 -250.410472)
		(width 0.18288)
		(layer "In2.Cu")
		(net "M_B_CPU0_SB_CA<3>")
	)
	(segment
		(start 332.719172 -249.075956)
		(end 332.375002 -249.075956)
		(width 0.088646)
		(layer "In2.Cu")
		(net "M_B_CPU0_SB_CA<3>")
	)
	(segment
		(start 307.303678 -250.7361)
		(end 307.110638 -250.54306)
		(width 0.18288)
		(layer "In2.Cu")
		(net "M_B_CPU0_SB_CA<3>")
	)
	(segment
		(start 311.860946 -250.224544)
		(end 310.653684 -250.224544)
		(width 0.18288)
		(layer "In2.Cu")
		(net "M_B_CPU0_SB_CA<3>")
	)
	(segment
		(start 318.22517 -250.603512)
		(end 318.03213 -250.410472)
		(width 0.18288)
		(layer "In2.Cu")
		(net "M_B_CPU0_SB_CA<3>")
	)
	(segment
		(start 299.654468 -250.666758)
		(end 299.004482 -250.016772)
		(width 0.18288)
		(layer "In2.Cu")
		(net "M_B_CPU0_SB_CA<3>")
	)
	(segment
		(start 312.248296 -250.611894)
		(end 311.860946 -250.224544)
		(width 0.18288)
		(layer "In2.Cu")
		(net "M_B_CPU0_SB_CA<3>")
	)
	(segment
		(start 307.110638 -250.54306)
		(end 307.110638 -250.33224)
		(width 0.18288)
		(layer "In2.Cu")
		(net "M_B_CPU0_SB_CA<3>")
	)
	(segment
		(start 315.109352 -249.495818)
		(end 314.789566 -249.815604)
		(width 0.18288)
		(layer "In2.Cu")
		(net "M_B_CPU0_SB_CA<3>")
	)
	(segment
		(start 306.572666 -250.146566)
		(end 306.213002 -250.50623)
		(width 0.18288)
		(layer "In2.Cu")
		(net "M_B_CPU0_SB_CA<3>")
	)
	(segment
		(start 333.735934 -248.367296)
		(end 333.427832 -248.367296)
		(width 0.088646)
		(layer "In2.Cu")
		(net "M_B_CPU0_SB_CA<3>")
	)
	(segment
		(start 313.910472 -250.410472)
		(end 313.70905 -250.611894)
		(width 0.18288)
		(layer "In2.Cu")
		(net "M_B_CPU0_SB_CA<3>")
	)
	(segment
		(start 318.22517 -251.260356)
		(end 318.22517 -250.603512)
		(width 0.18288)
		(layer "In2.Cu")
		(net "M_B_CPU0_SB_CA<3>")
	)
	(segment
		(start 315.382402 -249.495818)
		(end 315.109352 -249.495818)
		(width 0.18288)
		(layer "In2.Cu")
		(net "M_B_CPU0_SB_CA<3>")
	)
	(segment
		(start 332.375002 -249.075956)
		(end 329.57897 -249.075956)
		(width 0.18288)
		(layer "In2.Cu")
		(net "M_B_CPU0_SB_CA<3>")
	)
	(segment
		(start 319.63741 -250.603512)
		(end 319.44437 -250.410472)
		(width 0.18288)
		(layer "In2.Cu")
		(net "M_B_CPU0_SB_CA<3>")
	)
	(segment
		(start 319.12433 -250.410472)
		(end 318.93129 -250.603512)
		(width 0.18288)
		(layer "In2.Cu")
		(net "M_B_CPU0_SB_CA<3>")
	)
	(segment
		(start 336.367882 -248.316496)
		(end 336.357468 -248.3104)
		(width 0.088646)
		(layer "In2.Cu")
		(net "M_B_CPU0_SB_CA<3>")
	)
	(segment
		(start 337.965034 -248.806208)
		(end 337.336892 -248.33326)
		(width 0.088646)
		(layer "In2.Cu")
		(net "M_B_CPU0_SB_CA<3>")
	)
	(segment
		(start 321.217036 -250.410472)
		(end 320.53657 -250.410472)
		(width 0.18288)
		(layer "In2.Cu")
		(net "M_B_CPU0_SB_CA<3>")
	)
	(segment
		(start 307.110638 -250.33224)
		(end 306.924964 -250.146566)
		(width 0.18288)
		(layer "In2.Cu")
		(net "M_B_CPU0_SB_CA<3>")
	)
	(segment
		(start 329.57897 -249.075956)
		(end 328.44994 -247.946926)
		(width 0.18288)
		(layer "In2.Cu")
		(net "M_B_CPU0_SB_CA<3>")
	)
	(segment
		(start 302.356266 -250.56846)
		(end 301.897796 -250.10999)
		(width 0.18288)
		(layer "In2.Cu")
		(net "M_B_CPU0_SB_CA<3>")
	)
	(segment
		(start 320.34353 -250.603512)
		(end 320.34353 -251.260356)
		(width 0.18288)
		(layer "In2.Cu")
		(net "M_B_CPU0_SB_CA<3>")
	)
	(segment
		(start 314.789566 -250.217432)
		(end 314.596526 -250.410472)
		(width 0.18288)
		(layer "In2.Cu")
		(net "M_B_CPU0_SB_CA<3>")
	)
	(segment
		(start 304.67554 -250.50623)
		(end 304.315368 -250.146058)
		(width 0.18288)
		(layer "In2.Cu")
		(net "M_B_CPU0_SB_CA<3>")
	)
	(segment
		(start 337.336892 -248.33326)
		(end 337.307936 -248.31675)
		(width 0.088646)
		(layer "In2.Cu")
		(net "M_B_CPU0_SB_CA<3>")
	)
	(segment
		(start 309.852314 -250.502928)
		(end 309.439818 -250.090432)
		(width 0.18288)
		(layer "In2.Cu")
		(net "M_B_CPU0_SB_CA<3>")
	)
	(segment
		(start 308.318408 -250.090432)
		(end 307.953664 -250.455176)
		(width 0.18288)
		(layer "In2.Cu")
		(net "M_B_CPU0_SB_CA<3>")
	)
	(segment
		(start 318.41821 -251.453396)
		(end 318.22517 -251.260356)
		(width 0.18288)
		(layer "In2.Cu")
		(net "M_B_CPU0_SB_CA<3>")
	)
	(segment
		(start 300.2026 -250.666758)
		(end 299.654468 -250.666758)
		(width 0.18288)
		(layer "In2.Cu")
		(net "M_B_CPU0_SB_CA<3>")
	)
	(segment
		(start 307.777642 -250.7361)
		(end 307.303678 -250.7361)
		(width 0.18288)
		(layer "In2.Cu")
		(net "M_B_CPU0_SB_CA<3>")
	)
	(segment
		(start 307.953664 -250.560078)
		(end 307.777642 -250.7361)
		(width 0.18288)
		(layer "In2.Cu")
		(net "M_B_CPU0_SB_CA<3>")
	)
	(segment
		(start 315.575442 -249.688858)
		(end 315.382402 -249.495818)
		(width 0.18288)
		(layer "In2.Cu")
		(net "M_B_CPU0_SB_CA<3>")
	)
	(segment
		(start 314.789566 -249.815604)
		(end 314.789566 -250.217432)
		(width 0.18288)
		(layer "In2.Cu")
		(net "M_B_CPU0_SB_CA<3>")
	)
	(segment
		(start 306.213002 -250.50623)
		(end 304.67554 -250.50623)
		(width 0.18288)
		(layer "In2.Cu")
		(net "M_B_CPU0_SB_CA<3>")
	)
	(segment
		(start 318.93129 -250.603512)
		(end 318.93129 -251.260356)
		(width 0.18288)
		(layer "In2.Cu")
		(net "M_B_CPU0_SB_CA<3>")
	)
	(segment
		(start 320.15049 -251.453396)
		(end 319.83045 -251.453396)
		(width 0.18288)
		(layer "In2.Cu")
		(net "M_B_CPU0_SB_CA<3>")
	)
	(segment
		(start 318.73825 -251.453396)
		(end 318.41821 -251.453396)
		(width 0.18288)
		(layer "In2.Cu")
		(net "M_B_CPU0_SB_CA<3>")
	)
	(segment
		(start 319.44437 -250.410472)
		(end 319.12433 -250.410472)
		(width 0.18288)
		(layer "In2.Cu")
		(net "M_B_CPU0_SB_CA<3>")
	)
	(segment
		(start 320.53657 -250.410472)
		(end 320.34353 -250.603512)
		(width 0.18288)
		(layer "In2.Cu")
		(net "M_B_CPU0_SB_CA<3>")
	)
	(segment
		(start 309.439818 -250.090432)
		(end 308.318408 -250.090432)
		(width 0.18288)
		(layer "In2.Cu")
		(net "M_B_CPU0_SB_CA<3>")
	)
	(segment
		(start 302.794162 -250.56846)
		(end 302.356266 -250.56846)
		(width 0.18288)
		(layer "In2.Cu")
		(net "M_B_CPU0_SB_CA<3>")
	)
	(segment
		(start 318.03213 -250.410472)
		(end 315.83757 -250.410472)
		(width 0.18288)
		(layer "In2.Cu")
		(net "M_B_CPU0_SB_CA<3>")
	)
	(segment
		(start 303.216564 -250.146058)
		(end 302.794162 -250.56846)
		(width 0.18288)
		(layer "In2.Cu")
		(net "M_B_CPU0_SB_CA<3>")
	)
	(segment
		(start 318.93129 -251.260356)
		(end 318.73825 -251.453396)
		(width 0.18288)
		(layer "In2.Cu")
		(net "M_B_CPU0_SB_CA<3>")
	)
	(segment
		(start 313.70905 -250.611894)
		(end 312.248296 -250.611894)
		(width 0.18288)
		(layer "In2.Cu")
		(net "M_B_CPU0_SB_CA<3>")
	)
	(segment
		(start 310.653684 -250.224544)
		(end 310.3753 -250.502928)
		(width 0.18288)
		(layer "In2.Cu")
		(net "M_B_CPU0_SB_CA<3>")
	)
	(segment
		(start 310.3753 -250.502928)
		(end 309.852314 -250.502928)
		(width 0.18288)
		(layer "In2.Cu")
		(net "M_B_CPU0_SB_CA<3>")
	)
	(segment
		(start 300.759368 -250.10999)
		(end 300.2026 -250.666758)
		(width 0.18288)
		(layer "In2.Cu")
		(net "M_B_CPU0_SB_CA<3>")
	)
	(segment
		(start 315.575442 -250.148344)
		(end 315.575442 -249.688858)
		(width 0.18288)
		(layer "In2.Cu")
		(net "M_B_CPU0_SB_CA<3>")
	)
	(arc
		(start 334.862932 -248.316496)
		(mid 334.675734 -248.366639)
		(end 334.488536 -248.316496)
		(width 0.088646)
		(layer "In2.Cu")
		(net "M_B_CPU0_SB_CA<3>")
	)
	(arc
		(start 333.923132 -248.316496)
		(mid 333.832876 -248.354218)
		(end 333.735934 -248.367296)
		(width 0.088646)
		(layer "In2.Cu")
		(net "M_B_CPU0_SB_CA<3>")
	)
	(arc
		(start 337.307174 -248.316496)
		(mid 337.024726 -248.240813)
		(end 336.742278 -248.316496)
		(width 0.088646)
		(layer "In2.Cu")
		(net "M_B_CPU0_SB_CA<3>")
	)
	(arc
		(start 335.428336 -248.316496)
		(mid 335.145634 -248.240754)
		(end 334.862932 -248.316496)
		(width 0.088646)
		(layer "In2.Cu")
		(net "M_B_CPU0_SB_CA<3>")
	)
	(arc
		(start 335.802732 -248.316496)
		(mid 335.615534 -248.366639)
		(end 335.428336 -248.316496)
		(width 0.088646)
		(layer "In2.Cu")
		(net "M_B_CPU0_SB_CA<3>")
	)
	(arc
		(start 334.488536 -248.316496)
		(mid 334.205834 -248.240754)
		(end 333.923132 -248.316496)
		(width 0.088646)
		(layer "In2.Cu")
		(net "M_B_CPU0_SB_CA<3>")
	)
	(arc
		(start 336.742278 -248.316496)
		(mid 336.555224 -248.366546)
		(end 336.368136 -248.316496)
		(width 0.088646)
		(layer "In2.Cu")
		(net "M_B_CPU0_SB_CA<3>")
	)
	(arc
		(start 336.357468 -248.3104)
		(mid 336.07929 -248.240708)
		(end 335.802732 -248.316496)
		(width 0.088646)
		(layer "In2.Cu")
		(net "M_B_CPU0_SB_CA<3>")
	)
	(segment
		(start 287.801304 -251.077984)
		(end 287.589976 -250.866656)
		(width 0.20066)
		(layer "F.Cu")
		(net "M_B_CPU0_SB_CA<2>")
	)
	(segment
		(start 291.225986 -250.441714)
		(end 289.240468 -250.441714)
		(width 0.1016)
		(layer "F.Cu")
		(net "M_B_CPU0_SB_CA<2>")
	)
	(segment
		(start 287.589976 -250.866656)
		(end 286.255714 -250.866656)
		(width 0.20066)
		(layer "F.Cu")
		(net "M_B_CPU0_SB_CA<2>")
	)
	(segment
		(start 293.799514 -250.866656)
		(end 292.160198 -250.866656)
		(width 0.20066)
		(layer "F.Cu")
		(net "M_B_CPU0_SB_CA<2>")
	)
	(segment
		(start 291.735256 -250.441714)
		(end 291.556694 -250.441714)
		(width 0.20066)
		(layer "F.Cu")
		(net "M_B_CPU0_SB_CA<2>")
	)
	(segment
		(start 288.46018 -250.595384)
		(end 288.46018 -250.923552)
		(width 0.20066)
		(layer "F.Cu")
		(net "M_B_CPU0_SB_CA<2>")
	)
	(segment
		(start 289.240468 -250.441714)
		(end 289.231578 -250.432824)
		(width 0.1016)
		(layer "F.Cu")
		(net "M_B_CPU0_SB_CA<2>")
	)
	(segment
		(start 291.556694 -250.441714)
		(end 291.225986 -250.441714)
		(width 0.101854)
		(layer "F.Cu")
		(net "M_B_CPU0_SB_CA<2>")
	)
	(segment
		(start 288.46018 -250.923552)
		(end 288.305748 -251.077984)
		(width 0.20066)
		(layer "F.Cu")
		(net "M_B_CPU0_SB_CA<2>")
	)
	(segment
		(start 288.62274 -250.432824)
		(end 288.46018 -250.595384)
		(width 0.20066)
		(layer "F.Cu")
		(net "M_B_CPU0_SB_CA<2>")
	)
	(segment
		(start 337.025234 -249.341894)
		(end 337.025234 -248.806208)
		(width 0.20066)
		(layer "F.Cu")
		(net "M_B_CPU0_SB_CA<2>")
	)
	(segment
		(start 294.904414 -250.866656)
		(end 293.799514 -250.866656)
		(width 0.20066)
		(layer "F.Cu")
		(net "M_B_CPU0_SB_CA<2>")
	)
	(segment
		(start 292.160198 -250.866656)
		(end 291.735256 -250.441714)
		(width 0.20066)
		(layer "F.Cu")
		(net "M_B_CPU0_SB_CA<2>")
	)
	(segment
		(start 288.305748 -251.077984)
		(end 287.801304 -251.077984)
		(width 0.20066)
		(layer "F.Cu")
		(net "M_B_CPU0_SB_CA<2>")
	)
	(segment
		(start 289.231578 -250.432824)
		(end 288.62274 -250.432824)
		(width 0.20066)
		(layer "F.Cu")
		(net "M_B_CPU0_SB_CA<2>")
	)
	(segment
		(start 337.02498 -249.342148)
		(end 337.025234 -249.341894)
		(width 0.20066)
		(layer "F.Cu")
		(net "M_B_CPU0_SB_CA<2>")
	)
	(segment
		(start 300.315376 -251.178822)
		(end 299.9867 -251.178822)
		(width 0.18288)
		(layer "In2.Cu")
		(net "M_B_CPU0_SB_CA<2>")
	)
	(segment
		(start 310.119268 -251.014738)
		(end 309.874412 -251.259594)
		(width 0.18288)
		(layer "In2.Cu")
		(net "M_B_CPU0_SB_CA<2>")
	)
	(segment
		(start 327.96734 -248.292366)
		(end 324.05955 -248.292366)
		(width 0.18288)
		(layer "In2.Cu")
		(net "M_B_CPU0_SB_CA<2>")
	)
	(segment
		(start 317.822326 -251.99975)
		(end 317.629286 -251.80671)
		(width 0.18288)
		(layer "In2.Cu")
		(net "M_B_CPU0_SB_CA<2>")
	)
	(segment
		(start 314.83046 -250.977908)
		(end 314.361322 -251.447046)
		(width 0.18288)
		(layer "In2.Cu")
		(net "M_B_CPU0_SB_CA<2>")
	)
	(segment
		(start 324.05955 -248.292366)
		(end 320.352166 -251.99975)
		(width 0.18288)
		(layer "In2.Cu")
		(net "M_B_CPU0_SB_CA<2>")
	)
	(segment
		(start 317.629286 -251.80671)
		(end 317.629286 -251.170948)
		(width 0.18288)
		(layer "In2.Cu")
		(net "M_B_CPU0_SB_CA<2>")
	)
	(segment
		(start 295.388792 -251.351034)
		(end 294.904414 -250.866656)
		(width 0.18288)
		(layer "In2.Cu")
		(net "M_B_CPU0_SB_CA<2>")
	)
	(segment
		(start 306.098956 -251.305568)
		(end 305.810666 -251.017278)
		(width 0.18288)
		(layer "In2.Cu")
		(net "M_B_CPU0_SB_CA<2>")
	)
	(segment
		(start 333.735934 -248.557542)
		(end 333.542386 -248.557542)
		(width 0.088646)
		(layer "In2.Cu")
		(net "M_B_CPU0_SB_CA<2>")
	)
	(segment
		(start 296.574464 -252.038866)
		(end 295.977564 -252.038866)
		(width 0.18288)
		(layer "In2.Cu")
		(net "M_B_CPU0_SB_CA<2>")
	)
	(segment
		(start 317.629286 -251.170948)
		(end 317.436246 -250.977908)
		(width 0.18288)
		(layer "In2.Cu")
		(net "M_B_CPU0_SB_CA<2>")
	)
	(segment
		(start 295.784524 -251.544074)
		(end 295.591484 -251.351034)
		(width 0.18288)
		(layer "In2.Cu")
		(net "M_B_CPU0_SB_CA<2>")
	)
	(segment
		(start 332.678532 -249.421396)
		(end 332.375002 -249.421396)
		(width 0.088646)
		(layer "In2.Cu")
		(net "M_B_CPU0_SB_CA<2>")
	)
	(segment
		(start 306.832254 -251.305568)
		(end 306.098956 -251.305568)
		(width 0.18288)
		(layer "In2.Cu")
		(net "M_B_CPU0_SB_CA<2>")
	)
	(segment
		(start 299.9867 -251.178822)
		(end 299.873924 -251.291598)
		(width 0.18288)
		(layer "In2.Cu")
		(net "M_B_CPU0_SB_CA<2>")
	)
	(segment
		(start 312.28411 -251.12599)
		(end 312.065924 -251.344176)
		(width 0.18288)
		(layer "In2.Cu")
		(net "M_B_CPU0_SB_CA<2>")
	)
	(segment
		(start 295.977564 -252.038866)
		(end 295.784524 -251.845826)
		(width 0.18288)
		(layer "In2.Cu")
		(net "M_B_CPU0_SB_CA<2>")
	)
	(segment
		(start 299.873924 -251.291598)
		(end 296.961052 -251.291598)
		(width 0.18288)
		(layer "In2.Cu")
		(net "M_B_CPU0_SB_CA<2>")
	)
	(segment
		(start 302.362362 -251.08916)
		(end 302.11395 -251.337572)
		(width 0.18288)
		(layer "In2.Cu")
		(net "M_B_CPU0_SB_CA<2>")
	)
	(segment
		(start 336.272632 -248.481596)
		(end 336.272632 -248.48185)
		(width 0.088646)
		(layer "In2.Cu")
		(net "M_B_CPU0_SB_CA<2>")
	)
	(segment
		(start 312.065924 -251.344176)
		(end 311.668668 -251.344176)
		(width 0.18288)
		(layer "In2.Cu")
		(net "M_B_CPU0_SB_CA<2>")
	)
	(segment
		(start 314.361322 -251.447046)
		(end 314.052966 -251.447046)
		(width 0.18288)
		(layer "In2.Cu")
		(net "M_B_CPU0_SB_CA<2>")
	)
	(segment
		(start 296.961052 -251.291598)
		(end 296.767504 -251.485146)
		(width 0.18288)
		(layer "In2.Cu")
		(net "M_B_CPU0_SB_CA<2>")
	)
	(segment
		(start 296.767504 -251.485146)
		(end 296.767504 -251.845826)
		(width 0.18288)
		(layer "In2.Cu")
		(net "M_B_CPU0_SB_CA<2>")
	)
	(segment
		(start 329.09637 -249.421396)
		(end 327.96734 -248.292366)
		(width 0.18288)
		(layer "In2.Cu")
		(net "M_B_CPU0_SB_CA<2>")
	)
	(segment
		(start 337.025234 -248.806208)
		(end 336.302604 -248.499122)
		(width 0.088646)
		(layer "In2.Cu")
		(net "M_B_CPU0_SB_CA<2>")
	)
	(segment
		(start 296.767504 -251.845826)
		(end 296.574464 -252.038866)
		(width 0.18288)
		(layer "In2.Cu")
		(net "M_B_CPU0_SB_CA<2>")
	)
	(segment
		(start 304.817018 -251.017278)
		(end 304.534316 -251.29998)
		(width 0.18288)
		(layer "In2.Cu")
		(net "M_B_CPU0_SB_CA<2>")
	)
	(segment
		(start 333.542386 -248.557542)
		(end 332.678532 -249.421396)
		(width 0.088646)
		(layer "In2.Cu")
		(net "M_B_CPU0_SB_CA<2>")
	)
	(segment
		(start 311.668668 -251.344176)
		(end 311.33923 -251.014738)
		(width 0.18288)
		(layer "In2.Cu")
		(net "M_B_CPU0_SB_CA<2>")
	)
	(segment
		(start 311.33923 -251.014738)
		(end 310.119268 -251.014738)
		(width 0.18288)
		(layer "In2.Cu")
		(net "M_B_CPU0_SB_CA<2>")
	)
	(segment
		(start 336.302604 -248.499122)
		(end 336.272632 -248.481596)
		(width 0.088646)
		(layer "In2.Cu")
		(net "M_B_CPU0_SB_CA<2>")
	)
	(segment
		(start 309.874412 -251.259594)
		(end 306.878228 -251.259594)
		(width 0.18288)
		(layer "In2.Cu")
		(net "M_B_CPU0_SB_CA<2>")
	)
	(segment
		(start 300.474126 -251.337572)
		(end 300.315376 -251.178822)
		(width 0.18288)
		(layer "In2.Cu")
		(net "M_B_CPU0_SB_CA<2>")
	)
	(segment
		(start 317.436246 -250.977908)
		(end 314.83046 -250.977908)
		(width 0.18288)
		(layer "In2.Cu")
		(net "M_B_CPU0_SB_CA<2>")
	)
	(segment
		(start 320.352166 -251.99975)
		(end 317.822326 -251.99975)
		(width 0.18288)
		(layer "In2.Cu")
		(net "M_B_CPU0_SB_CA<2>")
	)
	(segment
		(start 305.810666 -251.017278)
		(end 304.817018 -251.017278)
		(width 0.18288)
		(layer "In2.Cu")
		(net "M_B_CPU0_SB_CA<2>")
	)
	(segment
		(start 295.784524 -251.845826)
		(end 295.784524 -251.544074)
		(width 0.18288)
		(layer "In2.Cu")
		(net "M_B_CPU0_SB_CA<2>")
	)
	(segment
		(start 302.11395 -251.337572)
		(end 300.474126 -251.337572)
		(width 0.18288)
		(layer "In2.Cu")
		(net "M_B_CPU0_SB_CA<2>")
	)
	(segment
		(start 306.878228 -251.259594)
		(end 306.832254 -251.305568)
		(width 0.18288)
		(layer "In2.Cu")
		(net "M_B_CPU0_SB_CA<2>")
	)
	(segment
		(start 332.375002 -249.421396)
		(end 329.09637 -249.421396)
		(width 0.18288)
		(layer "In2.Cu")
		(net "M_B_CPU0_SB_CA<2>")
	)
	(segment
		(start 304.534316 -251.29998)
		(end 303.323752 -251.29998)
		(width 0.18288)
		(layer "In2.Cu")
		(net "M_B_CPU0_SB_CA<2>")
	)
	(segment
		(start 303.112932 -251.08916)
		(end 302.362362 -251.08916)
		(width 0.18288)
		(layer "In2.Cu")
		(net "M_B_CPU0_SB_CA<2>")
	)
	(segment
		(start 314.052966 -251.447046)
		(end 313.73191 -251.12599)
		(width 0.18288)
		(layer "In2.Cu")
		(net "M_B_CPU0_SB_CA<2>")
	)
	(segment
		(start 303.323752 -251.29998)
		(end 303.112932 -251.08916)
		(width 0.18288)
		(layer "In2.Cu")
		(net "M_B_CPU0_SB_CA<2>")
	)
	(segment
		(start 313.73191 -251.12599)
		(end 312.28411 -251.12599)
		(width 0.18288)
		(layer "In2.Cu")
		(net "M_B_CPU0_SB_CA<2>")
	)
	(segment
		(start 295.591484 -251.351034)
		(end 295.388792 -251.351034)
		(width 0.18288)
		(layer "In2.Cu")
		(net "M_B_CPU0_SB_CA<2>")
	)
	(arc
		(start 336.272632 -248.48185)
		(mid 336.085434 -248.431707)
		(end 335.898236 -248.48185)
		(width 0.088646)
		(layer "In2.Cu")
		(net "M_B_CPU0_SB_CA<2>")
	)
	(arc
		(start 335.332832 -248.48185)
		(mid 335.145634 -248.431707)
		(end 334.958436 -248.48185)
		(width 0.088646)
		(layer "In2.Cu")
		(net "M_B_CPU0_SB_CA<2>")
	)
	(arc
		(start 334.018636 -248.48185)
		(mid 333.88227 -248.538328)
		(end 333.735934 -248.557542)
		(width 0.088646)
		(layer "In2.Cu")
		(net "M_B_CPU0_SB_CA<2>")
	)
	(arc
		(start 334.393032 -248.48185)
		(mid 334.205834 -248.431707)
		(end 334.018636 -248.48185)
		(width 0.088646)
		(layer "In2.Cu")
		(net "M_B_CPU0_SB_CA<2>")
	)
	(arc
		(start 334.958436 -248.48185)
		(mid 334.675734 -248.557592)
		(end 334.393032 -248.48185)
		(width 0.088646)
		(layer "In2.Cu")
		(net "M_B_CPU0_SB_CA<2>")
	)
	(arc
		(start 335.898236 -248.48185)
		(mid 335.615534 -248.557592)
		(end 335.332832 -248.48185)
		(width 0.088646)
		(layer "In2.Cu")
		(net "M_B_CPU0_SB_CA<2>")
	)
	(segment
		(start 292.321488 -252.15596)
		(end 292.178994 -252.013466)
		(width 0.20066)
		(layer "F.Cu")
		(net "M_B_CPU0_SB_CA<1>")
	)
	(segment
		(start 292.689534 -252.141736)
		(end 292.67531 -252.15596)
		(width 0.101854)
		(layer "F.Cu")
		(net "M_B_CPU0_SB_CA<1>")
	)
	(segment
		(start 297.08348 -251.716794)
		(end 296.875962 -251.924312)
		(width 0.20066)
		(layer "F.Cu")
		(net "M_B_CPU0_SB_CA<1>")
	)
	(segment
		(start 295.82237 -251.712476)
		(end 295.693846 -251.841)
		(width 0.20066)
		(layer "F.Cu")
		(net "M_B_CPU0_SB_CA<1>")
	)
	(segment
		(start 292.178994 -252.013466)
		(end 292.178994 -251.842778)
		(width 0.20066)
		(layer "F.Cu")
		(net "M_B_CPU0_SB_CA<1>")
	)
	(segment
		(start 292.67531 -252.15596)
		(end 292.321488 -252.15596)
		(width 0.20066)
		(layer "F.Cu")
		(net "M_B_CPU0_SB_CA<1>")
	)
	(segment
		(start 296.875962 -251.924312)
		(end 296.42943 -251.924312)
		(width 0.20066)
		(layer "F.Cu")
		(net "M_B_CPU0_SB_CA<1>")
	)
	(segment
		(start 295.000426 -252.141736)
		(end 292.927532 -252.141736)
		(width 0.1016)
		(layer "F.Cu")
		(net "M_B_CPU0_SB_CA<1>")
	)
	(segment
		(start 295.693846 -251.992638)
		(end 295.544748 -252.141736)
		(width 0.20066)
		(layer "F.Cu")
		(net "M_B_CPU0_SB_CA<1>")
	)
	(segment
		(start 340.314534 -248.528078)
		(end 340.31428 -248.527824)
		(width 0.20066)
		(layer "F.Cu")
		(net "M_B_CPU0_SB_CA<1>")
	)
	(segment
		(start 295.544748 -252.141736)
		(end 295.000426 -252.141736)
		(width 0.20066)
		(layer "F.Cu")
		(net "M_B_CPU0_SB_CA<1>")
	)
	(segment
		(start 295.693846 -251.841)
		(end 295.693846 -251.992638)
		(width 0.20066)
		(layer "F.Cu")
		(net "M_B_CPU0_SB_CA<1>")
	)
	(segment
		(start 297.899582 -251.716794)
		(end 297.08348 -251.716794)
		(width 0.20066)
		(layer "F.Cu")
		(net "M_B_CPU0_SB_CA<1>")
	)
	(segment
		(start 340.31428 -248.527824)
		(end 340.31428 -247.992138)
		(width 0.20066)
		(layer "F.Cu")
		(net "M_B_CPU0_SB_CA<1>")
	)
	(segment
		(start 299.004482 -251.716794)
		(end 297.899582 -251.716794)
		(width 0.20066)
		(layer "F.Cu")
		(net "M_B_CPU0_SB_CA<1>")
	)
	(segment
		(start 296.217594 -251.712476)
		(end 295.82237 -251.712476)
		(width 0.20066)
		(layer "F.Cu")
		(net "M_B_CPU0_SB_CA<1>")
	)
	(segment
		(start 292.927532 -252.141736)
		(end 292.689534 -252.141736)
		(width 0.101854)
		(layer "F.Cu")
		(net "M_B_CPU0_SB_CA<1>")
	)
	(segment
		(start 296.42943 -251.924312)
		(end 296.217594 -251.712476)
		(width 0.20066)
		(layer "F.Cu")
		(net "M_B_CPU0_SB_CA<1>")
	)
	(segment
		(start 292.178994 -251.842778)
		(end 292.05301 -251.716794)
		(width 0.20066)
		(layer "F.Cu")
		(net "M_B_CPU0_SB_CA<1>")
	)
	(segment
		(start 292.05301 -251.716794)
		(end 290.355782 -251.716794)
		(width 0.20066)
		(layer "F.Cu")
		(net "M_B_CPU0_SB_CA<1>")
	)
	(segment
		(start 311.720738 -252.11786)
		(end 311.27065 -251.667772)
		(width 0.18288)
		(layer "In2.Cu")
		(net "M_B_CPU0_SB_CA<1>")
	)
	(segment
		(start 303.280826 -251.826776)
		(end 302.96358 -252.144022)
		(width 0.18288)
		(layer "In2.Cu")
		(net "M_B_CPU0_SB_CA<1>")
	)
	(segment
		(start 327.584308 -248.637806)
		(end 324.436994 -248.637806)
		(width 0.18288)
		(layer "In2.Cu")
		(net "M_B_CPU0_SB_CA<1>")
	)
	(segment
		(start 314.863226 -251.92482)
		(end 314.670186 -252.11786)
		(width 0.18288)
		(layer "In2.Cu")
		(net "M_B_CPU0_SB_CA<1>")
	)
	(segment
		(start 333.73568 -249.05462)
		(end 333.502508 -249.05462)
		(width 0.088646)
		(layer "In2.Cu")
		(net "M_B_CPU0_SB_CA<1>")
	)
	(segment
		(start 317.298324 -252.516894)
		(end 317.105284 -252.323854)
		(width 0.18288)
		(layer "In2.Cu")
		(net "M_B_CPU0_SB_CA<1>")
	)
	(segment
		(start 311.27065 -251.667772)
		(end 310.858154 -251.667772)
		(width 0.18288)
		(layer "In2.Cu")
		(net "M_B_CPU0_SB_CA<1>")
	)
	(segment
		(start 317.105284 -251.708158)
		(end 316.912244 -251.515118)
		(width 0.18288)
		(layer "In2.Cu")
		(net "M_B_CPU0_SB_CA<1>")
	)
	(segment
		(start 316.315852 -251.708158)
		(end 316.315852 -252.34392)
		(width 0.18288)
		(layer "In2.Cu")
		(net "M_B_CPU0_SB_CA<1>")
	)
	(segment
		(start 304.236628 -251.826776)
		(end 303.280826 -251.826776)
		(width 0.18288)
		(layer "In2.Cu")
		(net "M_B_CPU0_SB_CA<1>")
	)
	(segment
		(start 316.315852 -252.34392)
		(end 316.122812 -252.53696)
		(width 0.18288)
		(layer "In2.Cu")
		(net "M_B_CPU0_SB_CA<1>")
	)
	(segment
		(start 315.397134 -251.515118)
		(end 315.056266 -251.515118)
		(width 0.18288)
		(layer "In2.Cu")
		(net "M_B_CPU0_SB_CA<1>")
	)
	(segment
		(start 335.347564 -249.12193)
		(end 335.332832 -249.130566)
		(width 0.088646)
		(layer "In2.Cu")
		(net "M_B_CPU0_SB_CA<1>")
	)
	(segment
		(start 314.670186 -252.11786)
		(end 311.720738 -252.11786)
		(width 0.18288)
		(layer "In2.Cu")
		(net "M_B_CPU0_SB_CA<1>")
	)
	(segment
		(start 336.287364 -249.12193)
		(end 336.272632 -249.130566)
		(width 0.088646)
		(layer "In2.Cu")
		(net "M_B_CPU0_SB_CA<1>")
	)
	(segment
		(start 302.96358 -252.144022)
		(end 299.43171 -252.144022)
		(width 0.18288)
		(layer "In2.Cu")
		(net "M_B_CPU0_SB_CA<1>")
	)
	(segment
		(start 328.713338 -249.766836)
		(end 327.584308 -248.637806)
		(width 0.18288)
		(layer "In2.Cu")
		(net "M_B_CPU0_SB_CA<1>")
	)
	(segment
		(start 310.858154 -251.667772)
		(end 310.378856 -252.14707)
		(width 0.18288)
		(layer "In2.Cu")
		(net "M_B_CPU0_SB_CA<1>")
	)
	(segment
		(start 332.790292 -249.766836)
		(end 332.375002 -249.766836)
		(width 0.088646)
		(layer "In2.Cu")
		(net "M_B_CPU0_SB_CA<1>")
	)
	(segment
		(start 299.43171 -252.144022)
		(end 299.004482 -251.716794)
		(width 0.18288)
		(layer "In2.Cu")
		(net "M_B_CPU0_SB_CA<1>")
	)
	(segment
		(start 333.502508 -249.05462)
		(end 332.790292 -249.766836)
		(width 0.088646)
		(layer "In2.Cu")
		(net "M_B_CPU0_SB_CA<1>")
	)
	(segment
		(start 316.122812 -252.53696)
		(end 315.783214 -252.53696)
		(width 0.18288)
		(layer "In2.Cu")
		(net "M_B_CPU0_SB_CA<1>")
	)
	(segment
		(start 304.556922 -252.14707)
		(end 304.236628 -251.826776)
		(width 0.18288)
		(layer "In2.Cu")
		(net "M_B_CPU0_SB_CA<1>")
	)
	(segment
		(start 337.227164 -249.12193)
		(end 337.212432 -249.130566)
		(width 0.088646)
		(layer "In2.Cu")
		(net "M_B_CPU0_SB_CA<1>")
	)
	(segment
		(start 324.436994 -248.637806)
		(end 320.557906 -252.516894)
		(width 0.18288)
		(layer "In2.Cu")
		(net "M_B_CPU0_SB_CA<1>")
	)
	(segment
		(start 339.591142 -248.299478)
		(end 339.561932 -248.316496)
		(width 0.088646)
		(layer "In2.Cu")
		(net "M_B_CPU0_SB_CA<1>")
	)
	(segment
		(start 315.590174 -252.34392)
		(end 315.590174 -251.708158)
		(width 0.18288)
		(layer "In2.Cu")
		(net "M_B_CPU0_SB_CA<1>")
	)
	(segment
		(start 334.407764 -249.12193)
		(end 334.393032 -249.130566)
		(width 0.088646)
		(layer "In2.Cu")
		(net "M_B_CPU0_SB_CA<1>")
	)
	(segment
		(start 340.31428 -247.992138)
		(end 339.591142 -248.299478)
		(width 0.088646)
		(layer "In2.Cu")
		(net "M_B_CPU0_SB_CA<1>")
	)
	(segment
		(start 315.590174 -251.708158)
		(end 315.397134 -251.515118)
		(width 0.18288)
		(layer "In2.Cu")
		(net "M_B_CPU0_SB_CA<1>")
	)
	(segment
		(start 332.375002 -249.766836)
		(end 328.713338 -249.766836)
		(width 0.18288)
		(layer "In2.Cu")
		(net "M_B_CPU0_SB_CA<1>")
	)
	(segment
		(start 310.378856 -252.14707)
		(end 304.556922 -252.14707)
		(width 0.18288)
		(layer "In2.Cu")
		(net "M_B_CPU0_SB_CA<1>")
	)
	(segment
		(start 315.783214 -252.53696)
		(end 315.590174 -252.34392)
		(width 0.18288)
		(layer "In2.Cu")
		(net "M_B_CPU0_SB_CA<1>")
	)
	(segment
		(start 316.508892 -251.515118)
		(end 316.315852 -251.708158)
		(width 0.18288)
		(layer "In2.Cu")
		(net "M_B_CPU0_SB_CA<1>")
	)
	(segment
		(start 338.161122 -249.125486)
		(end 338.152232 -249.130566)
		(width 0.088646)
		(layer "In2.Cu")
		(net "M_B_CPU0_SB_CA<1>")
	)
	(segment
		(start 316.912244 -251.515118)
		(end 316.508892 -251.515118)
		(width 0.18288)
		(layer "In2.Cu")
		(net "M_B_CPU0_SB_CA<1>")
	)
	(segment
		(start 314.863226 -251.708158)
		(end 314.863226 -251.92482)
		(width 0.18288)
		(layer "In2.Cu")
		(net "M_B_CPU0_SB_CA<1>")
	)
	(segment
		(start 315.056266 -251.515118)
		(end 314.863226 -251.708158)
		(width 0.18288)
		(layer "In2.Cu")
		(net "M_B_CPU0_SB_CA<1>")
	)
	(segment
		(start 320.557906 -252.516894)
		(end 317.298324 -252.516894)
		(width 0.18288)
		(layer "In2.Cu")
		(net "M_B_CPU0_SB_CA<1>")
	)
	(segment
		(start 338.33943 -248.791984)
		(end 338.339684 -248.806208)
		(width 0.088646)
		(layer "In2.Cu")
		(net "M_B_CPU0_SB_CA<1>")
	)
	(segment
		(start 317.105284 -252.323854)
		(end 317.105284 -251.708158)
		(width 0.18288)
		(layer "In2.Cu")
		(net "M_B_CPU0_SB_CA<1>")
	)
	(arc
		(start 335.332832 -249.130566)
		(mid 335.145634 -249.180709)
		(end 334.958436 -249.130566)
		(width 0.088646)
		(layer "In2.Cu")
		(net "M_B_CPU0_SB_CA<1>")
	)
	(arc
		(start 338.152232 -249.130566)
		(mid 337.965034 -249.180709)
		(end 337.777836 -249.130566)
		(width 0.088646)
		(layer "In2.Cu")
		(net "M_B_CPU0_SB_CA<1>")
	)
	(arc
		(start 334.018636 -249.130566)
		(mid 333.882164 -249.073943)
		(end 333.73568 -249.05462)
		(width 0.088646)
		(layer "In2.Cu")
		(net "M_B_CPU0_SB_CA<1>")
	)
	(arc
		(start 339.561932 -248.316496)
		(mid 339.374734 -248.366639)
		(end 339.187536 -248.316496)
		(width 0.088646)
		(layer "In2.Cu")
		(net "M_B_CPU0_SB_CA<1>")
	)
	(arc
		(start 336.838036 -249.130566)
		(mid 336.563837 -249.054731)
		(end 336.287364 -249.12193)
		(width 0.088646)
		(layer "In2.Cu")
		(net "M_B_CPU0_SB_CA<1>")
	)
	(arc
		(start 335.898236 -249.130566)
		(mid 335.624037 -249.054731)
		(end 335.347564 -249.12193)
		(width 0.088646)
		(layer "In2.Cu")
		(net "M_B_CPU0_SB_CA<1>")
	)
	(arc
		(start 334.958436 -249.130566)
		(mid 334.684237 -249.054731)
		(end 334.407764 -249.12193)
		(width 0.088646)
		(layer "In2.Cu")
		(net "M_B_CPU0_SB_CA<1>")
	)
	(arc
		(start 338.339684 -248.806208)
		(mid 338.292005 -248.989108)
		(end 338.161122 -249.125486)
		(width 0.088646)
		(layer "In2.Cu")
		(net "M_B_CPU0_SB_CA<1>")
	)
	(arc
		(start 337.212432 -249.130566)
		(mid 337.025234 -249.180709)
		(end 336.838036 -249.130566)
		(width 0.088646)
		(layer "In2.Cu")
		(net "M_B_CPU0_SB_CA<1>")
	)
	(arc
		(start 337.777836 -249.130566)
		(mid 337.503637 -249.054731)
		(end 337.227164 -249.12193)
		(width 0.088646)
		(layer "In2.Cu")
		(net "M_B_CPU0_SB_CA<1>")
	)
	(arc
		(start 339.187536 -248.316496)
		(mid 338.628275 -248.313001)
		(end 338.33943 -248.791984)
		(width 0.088646)
		(layer "In2.Cu")
		(net "M_B_CPU0_SB_CA<1>")
	)
	(arc
		(start 334.393032 -249.130566)
		(mid 334.205834 -249.180709)
		(end 334.018636 -249.130566)
		(width 0.088646)
		(layer "In2.Cu")
		(net "M_B_CPU0_SB_CA<1>")
	)
	(arc
		(start 336.272632 -249.130566)
		(mid 336.085434 -249.180709)
		(end 335.898236 -249.130566)
		(width 0.088646)
		(layer "In2.Cu")
		(net "M_B_CPU0_SB_CA<1>")
	)
	(segment
		(start 292.160198 -252.566678)
		(end 291.735256 -252.141736)
		(width 0.20066)
		(layer "F.Cu")
		(net "M_B_CPU0_SB_CA<0>")
	)
	(segment
		(start 291.735256 -252.141736)
		(end 291.556694 -252.141736)
		(width 0.20066)
		(layer "F.Cu")
		(net "M_B_CPU0_SB_CA<0>")
	)
	(segment
		(start 288.305748 -252.778006)
		(end 287.801304 -252.778006)
		(width 0.20066)
		(layer "F.Cu")
		(net "M_B_CPU0_SB_CA<0>")
	)
	(segment
		(start 291.225986 -252.141736)
		(end 289.240468 -252.141736)
		(width 0.1016)
		(layer "F.Cu")
		(net "M_B_CPU0_SB_CA<0>")
	)
	(segment
		(start 287.801304 -252.778006)
		(end 287.589976 -252.566678)
		(width 0.20066)
		(layer "F.Cu")
		(net "M_B_CPU0_SB_CA<0>")
	)
	(segment
		(start 293.799514 -252.566678)
		(end 292.160198 -252.566678)
		(width 0.20066)
		(layer "F.Cu")
		(net "M_B_CPU0_SB_CA<0>")
	)
	(segment
		(start 288.46018 -252.295406)
		(end 288.46018 -252.623574)
		(width 0.20066)
		(layer "F.Cu")
		(net "M_B_CPU0_SB_CA<0>")
	)
	(segment
		(start 339.84438 -249.342148)
		(end 339.844634 -249.341894)
		(width 0.20066)
		(layer "F.Cu")
		(net "M_B_CPU0_SB_CA<0>")
	)
	(segment
		(start 287.589976 -252.566678)
		(end 286.255714 -252.566678)
		(width 0.20066)
		(layer "F.Cu")
		(net "M_B_CPU0_SB_CA<0>")
	)
	(segment
		(start 294.904414 -252.566678)
		(end 293.799514 -252.566678)
		(width 0.20066)
		(layer "F.Cu")
		(net "M_B_CPU0_SB_CA<0>")
	)
	(segment
		(start 288.46018 -252.623574)
		(end 288.305748 -252.778006)
		(width 0.20066)
		(layer "F.Cu")
		(net "M_B_CPU0_SB_CA<0>")
	)
	(segment
		(start 291.556694 -252.141736)
		(end 291.225986 -252.141736)
		(width 0.101854)
		(layer "F.Cu")
		(net "M_B_CPU0_SB_CA<0>")
	)
	(segment
		(start 289.240468 -252.141736)
		(end 289.231578 -252.132846)
		(width 0.1016)
		(layer "F.Cu")
		(net "M_B_CPU0_SB_CA<0>")
	)
	(segment
		(start 339.844634 -249.341894)
		(end 339.844634 -248.806208)
		(width 0.20066)
		(layer "F.Cu")
		(net "M_B_CPU0_SB_CA<0>")
	)
	(segment
		(start 289.231578 -252.132846)
		(end 288.62274 -252.132846)
		(width 0.20066)
		(layer "F.Cu")
		(net "M_B_CPU0_SB_CA<0>")
	)
	(segment
		(start 288.62274 -252.132846)
		(end 288.46018 -252.295406)
		(width 0.20066)
		(layer "F.Cu")
		(net "M_B_CPU0_SB_CA<0>")
	)
	(segment
		(start 296.954956 -253.059184)
		(end 296.46245 -252.566678)
		(width 0.18288)
		(layer "In2.Cu")
		(net "M_B_CPU0_SB_CA<0>")
	)
	(segment
		(start 332.714092 -250.112276)
		(end 332.375002 -250.112276)
		(width 0.088646)
		(layer "In2.Cu")
		(net "M_B_CPU0_SB_CA<0>")
	)
	(segment
		(start 332.375002 -250.112276)
		(end 328.359516 -250.112276)
		(width 0.18288)
		(layer "In2.Cu")
		(net "M_B_CPU0_SB_CA<0>")
	)
	(segment
		(start 328.359516 -250.112276)
		(end 327.230486 -248.983246)
		(width 0.18288)
		(layer "In2.Cu")
		(net "M_B_CPU0_SB_CA<0>")
	)
	(segment
		(start 296.46245 -252.566678)
		(end 294.904414 -252.566678)
		(width 0.18288)
		(layer "In2.Cu")
		(net "M_B_CPU0_SB_CA<0>")
	)
	(segment
		(start 339.844634 -248.806208)
		(end 339.48116 -248.705116)
		(width 0.088646)
		(layer "In2.Cu")
		(net "M_B_CPU0_SB_CA<0>")
	)
	(segment
		(start 338.717382 -248.48185)
		(end 338.708492 -248.48693)
		(width 0.088646)
		(layer "In2.Cu")
		(net "M_B_CPU0_SB_CA<0>")
	)
	(segment
		(start 337.307682 -249.295666)
		(end 337.29295 -249.304302)
		(width 0.088646)
		(layer "In2.Cu")
		(net "M_B_CPU0_SB_CA<0>")
	)
	(segment
		(start 324.81139 -248.983246)
		(end 320.735452 -253.059184)
		(width 0.18288)
		(layer "In2.Cu")
		(net "M_B_CPU0_SB_CA<0>")
	)
	(segment
		(start 338.52993 -248.806208)
		(end 338.530184 -248.806208)
		(width 0.088646)
		(layer "In2.Cu")
		(net "M_B_CPU0_SB_CA<0>")
	)
	(segment
		(start 336.367882 -249.295666)
		(end 336.35315 -249.304302)
		(width 0.088646)
		(layer "In2.Cu")
		(net "M_B_CPU0_SB_CA<0>")
	)
	(segment
		(start 338.247736 -249.295666)
		(end 338.237322 -249.301762)
		(width 0.088646)
		(layer "In2.Cu")
		(net "M_B_CPU0_SB_CA<0>")
	)
	(segment
		(start 320.735452 -253.059184)
		(end 296.954956 -253.059184)
		(width 0.18288)
		(layer "In2.Cu")
		(net "M_B_CPU0_SB_CA<0>")
	)
	(segment
		(start 334.488282 -249.295666)
		(end 334.47355 -249.304302)
		(width 0.088646)
		(layer "In2.Cu")
		(net "M_B_CPU0_SB_CA<0>")
	)
	(segment
		(start 333.73568 -249.244866)
		(end 333.581502 -249.244866)
		(width 0.088646)
		(layer "In2.Cu")
		(net "M_B_CPU0_SB_CA<0>")
	)
	(segment
		(start 333.581502 -249.244866)
		(end 332.714092 -250.112276)
		(width 0.088646)
		(layer "In2.Cu")
		(net "M_B_CPU0_SB_CA<0>")
	)
	(segment
		(start 335.428082 -249.295666)
		(end 335.41335 -249.304302)
		(width 0.088646)
		(layer "In2.Cu")
		(net "M_B_CPU0_SB_CA<0>")
	)
	(segment
		(start 327.230486 -248.983246)
		(end 324.81139 -248.983246)
		(width 0.18288)
		(layer "In2.Cu")
		(net "M_B_CPU0_SB_CA<0>")
	)
	(segment
		(start 338.530184 -248.806208)
		(end 338.530184 -248.816114)
		(width 0.088646)
		(layer "In2.Cu")
		(net "M_B_CPU0_SB_CA<0>")
	)
	(arc
		(start 338.237322 -249.301762)
		(mid 337.95889 -249.371608)
		(end 337.682078 -249.295666)
		(width 0.088646)
		(layer "In2.Cu")
		(net "M_B_CPU0_SB_CA<0>")
	)
	(arc
		(start 334.862678 -249.295666)
		(mid 334.67548 -249.245523)
		(end 334.488282 -249.295666)
		(width 0.088646)
		(layer "In2.Cu")
		(net "M_B_CPU0_SB_CA<0>")
	)
	(arc
		(start 339.48116 -248.705116)
		(mid 339.369458 -248.626623)
		(end 339.252306 -248.556526)
		(width 0.088646)
		(layer "In2.Cu")
		(net "M_B_CPU0_SB_CA<0>")
	)
	(arc
		(start 337.682078 -249.295666)
		(mid 337.49488 -249.245523)
		(end 337.307682 -249.295666)
		(width 0.088646)
		(layer "In2.Cu")
		(net "M_B_CPU0_SB_CA<0>")
	)
	(arc
		(start 339.092286 -248.481342)
		(mid 339.079341 -248.474224)
		(end 339.066124 -248.467626)
		(width 0.088646)
		(layer "In2.Cu")
		(net "M_B_CPU0_SB_CA<0>")
	)
	(arc
		(start 339.066124 -248.467626)
		(mid 339.054583 -248.462888)
		(end 339.04301 -248.458228)
		(width 0.088646)
		(layer "In2.Cu")
		(net "M_B_CPU0_SB_CA<0>")
	)
	(arc
		(start 338.530184 -248.816114)
		(mid 338.452073 -249.093063)
		(end 338.247736 -249.295666)
		(width 0.088646)
		(layer "In2.Cu")
		(net "M_B_CPU0_SB_CA<0>")
	)
	(arc
		(start 333.922878 -249.295666)
		(mid 333.832622 -249.257944)
		(end 333.73568 -249.244866)
		(width 0.088646)
		(layer "In2.Cu")
		(net "M_B_CPU0_SB_CA<0>")
	)
	(arc
		(start 338.734654 -248.472706)
		(mid 338.725942 -248.477134)
		(end 338.717382 -248.48185)
		(width 0.088646)
		(layer "In2.Cu")
		(net "M_B_CPU0_SB_CA<0>")
	)
	(arc
		(start 335.41335 -249.304302)
		(mid 335.136875 -249.371622)
		(end 334.862678 -249.295666)
		(width 0.088646)
		(layer "In2.Cu")
		(net "M_B_CPU0_SB_CA<0>")
	)
	(arc
		(start 335.802478 -249.295666)
		(mid 335.61528 -249.245523)
		(end 335.428082 -249.295666)
		(width 0.088646)
		(layer "In2.Cu")
		(net "M_B_CPU0_SB_CA<0>")
	)
	(arc
		(start 339.04301 -248.458228)
		(mid 338.887271 -248.43221)
		(end 338.734654 -248.472706)
		(width 0.088646)
		(layer "In2.Cu")
		(net "M_B_CPU0_SB_CA<0>")
	)
	(arc
		(start 337.29295 -249.304302)
		(mid 337.016475 -249.371622)
		(end 336.742278 -249.295666)
		(width 0.088646)
		(layer "In2.Cu")
		(net "M_B_CPU0_SB_CA<0>")
	)
	(arc
		(start 339.17128 -248.519442)
		(mid 339.131045 -248.501922)
		(end 339.092286 -248.481342)
		(width 0.088646)
		(layer "In2.Cu")
		(net "M_B_CPU0_SB_CA<0>")
	)
	(arc
		(start 338.708492 -248.48693)
		(mid 338.577578 -248.62329)
		(end 338.52993 -248.806208)
		(width 0.088646)
		(layer "In2.Cu")
		(net "M_B_CPU0_SB_CA<0>")
	)
	(arc
		(start 336.742278 -249.295666)
		(mid 336.55508 -249.245523)
		(end 336.367882 -249.295666)
		(width 0.088646)
		(layer "In2.Cu")
		(net "M_B_CPU0_SB_CA<0>")
	)
	(arc
		(start 334.47355 -249.304302)
		(mid 334.197075 -249.371622)
		(end 333.922878 -249.295666)
		(width 0.088646)
		(layer "In2.Cu")
		(net "M_B_CPU0_SB_CA<0>")
	)
	(arc
		(start 336.35315 -249.304302)
		(mid 336.076675 -249.371622)
		(end 335.802478 -249.295666)
		(width 0.088646)
		(layer "In2.Cu")
		(net "M_B_CPU0_SB_CA<0>")
	)
	(arc
		(start 339.252306 -248.556526)
		(mid 339.212415 -248.536625)
		(end 339.17128 -248.519442)
		(width 0.088646)
		(layer "In2.Cu")
		(net "M_B_CPU0_SB_CA<0>")
	)
	(segment
		(start 346.532962 -253.383796)
		(end 346.532962 -253.919482)
		(width 0.20066)
		(layer "F.Cu")
		(net "M_B_CPU0_SA_RSP<1>")
	)
	(segment
		(start 294.904414 -244.066568)
		(end 293.799514 -244.066568)
		(width 0.20066)
		(layer "F.Cu")
		(net "M_B_CPU0_SA_RSP<1>")
	)
	(segment
		(start 346.532962 -253.919482)
		(end 346.533216 -253.919736)
		(width 0.20066)
		(layer "F.Cu")
		(net "M_B_CPU0_SA_RSP<1>")
	)
	(segment
		(start 301.916084 -247.672606)
		(end 301.225204 -247.672606)
		(width 0.18288)
		(layer "In6.Cu")
		(net "M_B_CPU0_SA_RSP<1>")
	)
	(segment
		(start 346.532962 -252.781308)
		(end 346.532962 -252.086618)
		(width 0.18288)
		(layer "In6.Cu")
		(net "M_B_CPU0_SA_RSP<1>")
	)
	(segment
		(start 335.941162 -251.456444)
		(end 335.746852 -251.262134)
		(width 0.18288)
		(layer "In6.Cu")
		(net "M_B_CPU0_SA_RSP<1>")
	)
	(segment
		(start 299.285406 -246.191024)
		(end 298.062396 -246.191024)
		(width 0.18288)
		(layer "In6.Cu")
		(net "M_B_CPU0_SA_RSP<1>")
	)
	(segment
		(start 315.511434 -250.823984)
		(end 314.625228 -249.937778)
		(width 0.18288)
		(layer "In6.Cu")
		(net "M_B_CPU0_SA_RSP<1>")
	)
	(segment
		(start 320.897758 -251.355606)
		(end 316.79515 -251.355606)
		(width 0.18288)
		(layer "In6.Cu")
		(net "M_B_CPU0_SA_RSP<1>")
	)
	(segment
		(start 302.606964 -247.0658)
		(end 302.281844 -247.0658)
		(width 0.18288)
		(layer "In6.Cu")
		(net "M_B_CPU0_SA_RSP<1>")
	)
	(segment
		(start 314.625228 -249.937778)
		(end 312.344308 -248.992898)
		(width 0.18288)
		(layer "In6.Cu")
		(net "M_B_CPU0_SA_RSP<1>")
	)
	(segment
		(start 346.532962 -253.032006)
		(end 346.532962 -252.781308)
		(width 0.088646)
		(layer "In6.Cu")
		(net "M_B_CPU0_SA_RSP<1>")
	)
	(segment
		(start 309.124604 -249.650504)
		(end 309.124604 -249.937016)
		(width 0.18288)
		(layer "In6.Cu")
		(net "M_B_CPU0_SA_RSP<1>")
	)
	(segment
		(start 345.902788 -251.456444)
		(end 335.941162 -251.456444)
		(width 0.18288)
		(layer "In6.Cu")
		(net "M_B_CPU0_SA_RSP<1>")
	)
	(segment
		(start 316.79515 -251.355606)
		(end 315.511434 -250.823984)
		(width 0.18288)
		(layer "In6.Cu")
		(net "M_B_CPU0_SA_RSP<1>")
	)
	(segment
		(start 305.121818 -249.10669)
		(end 304.938938 -248.92381)
		(width 0.18288)
		(layer "In6.Cu")
		(net "M_B_CPU0_SA_RSP<1>")
	)
	(segment
		(start 305.812698 -247.915938)
		(end 305.629818 -248.098818)
		(width 0.18288)
		(layer "In6.Cu")
		(net "M_B_CPU0_SA_RSP<1>")
	)
	(segment
		(start 304.756058 -247.915938)
		(end 303.676812 -247.915938)
		(width 0.18288)
		(layer "In6.Cu")
		(net "M_B_CPU0_SA_RSP<1>")
	)
	(segment
		(start 301.225204 -247.672606)
		(end 300.780958 -247.22836)
		(width 0.18288)
		(layer "In6.Cu")
		(net "M_B_CPU0_SA_RSP<1>")
	)
	(segment
		(start 305.446938 -249.10669)
		(end 305.121818 -249.10669)
		(width 0.18288)
		(layer "In6.Cu")
		(net "M_B_CPU0_SA_RSP<1>")
	)
	(segment
		(start 300.458632 -246.120666)
		(end 299.355764 -246.120666)
		(width 0.18288)
		(layer "In6.Cu")
		(net "M_B_CPU0_SA_RSP<1>")
	)
	(segment
		(start 304.938938 -248.92381)
		(end 304.938938 -248.098818)
		(width 0.18288)
		(layer "In6.Cu")
		(net "M_B_CPU0_SA_RSP<1>")
	)
	(segment
		(start 307.202332 -248.266966)
		(end 306.851304 -247.915938)
		(width 0.18288)
		(layer "In6.Cu")
		(net "M_B_CPU0_SA_RSP<1>")
	)
	(segment
		(start 308.616604 -250.119896)
		(end 308.433724 -249.937016)
		(width 0.18288)
		(layer "In6.Cu")
		(net "M_B_CPU0_SA_RSP<1>")
	)
	(segment
		(start 308.433724 -249.650504)
		(end 308.250844 -249.467624)
		(width 0.18288)
		(layer "In6.Cu")
		(net "M_B_CPU0_SA_RSP<1>")
	)
	(segment
		(start 308.250844 -249.467624)
		(end 307.559964 -249.467624)
		(width 0.18288)
		(layer "In6.Cu")
		(net "M_B_CPU0_SA_RSP<1>")
	)
	(segment
		(start 302.789844 -247.24868)
		(end 302.606964 -247.0658)
		(width 0.18288)
		(layer "In6.Cu")
		(net "M_B_CPU0_SA_RSP<1>")
	)
	(segment
		(start 307.202332 -249.109992)
		(end 307.202332 -248.266966)
		(width 0.18288)
		(layer "In6.Cu")
		(net "M_B_CPU0_SA_RSP<1>")
	)
	(segment
		(start 304.938938 -248.098818)
		(end 304.756058 -247.915938)
		(width 0.18288)
		(layer "In6.Cu")
		(net "M_B_CPU0_SA_RSP<1>")
	)
	(segment
		(start 299.355764 -246.120666)
		(end 299.285406 -246.191024)
		(width 0.18288)
		(layer "In6.Cu")
		(net "M_B_CPU0_SA_RSP<1>")
	)
	(segment
		(start 305.629818 -248.92381)
		(end 305.446938 -249.10669)
		(width 0.18288)
		(layer "In6.Cu")
		(net "M_B_CPU0_SA_RSP<1>")
	)
	(segment
		(start 312.00598 -248.65457)
		(end 311.211722 -248.65457)
		(width 0.18288)
		(layer "In6.Cu")
		(net "M_B_CPU0_SA_RSP<1>")
	)
	(segment
		(start 300.780958 -247.22836)
		(end 300.780958 -246.442992)
		(width 0.18288)
		(layer "In6.Cu")
		(net "M_B_CPU0_SA_RSP<1>")
	)
	(segment
		(start 297.179238 -245.307866)
		(end 296.145712 -245.307866)
		(width 0.18288)
		(layer "In6.Cu")
		(net "M_B_CPU0_SA_RSP<1>")
	)
	(segment
		(start 302.789844 -247.489726)
		(end 302.789844 -247.24868)
		(width 0.18288)
		(layer "In6.Cu")
		(net "M_B_CPU0_SA_RSP<1>")
	)
	(segment
		(start 300.780958 -246.442992)
		(end 300.458632 -246.120666)
		(width 0.18288)
		(layer "In6.Cu")
		(net "M_B_CPU0_SA_RSP<1>")
	)
	(segment
		(start 346.532962 -252.086618)
		(end 345.902788 -251.456444)
		(width 0.18288)
		(layer "In6.Cu")
		(net "M_B_CPU0_SA_RSP<1>")
	)
	(segment
		(start 310.398668 -249.467624)
		(end 309.307484 -249.467624)
		(width 0.18288)
		(layer "In6.Cu")
		(net "M_B_CPU0_SA_RSP<1>")
	)
	(segment
		(start 327.23328 -248.656094)
		(end 323.59727 -248.656094)
		(width 0.18288)
		(layer "In6.Cu")
		(net "M_B_CPU0_SA_RSP<1>")
	)
	(segment
		(start 309.307484 -249.467624)
		(end 309.124604 -249.650504)
		(width 0.18288)
		(layer "In6.Cu")
		(net "M_B_CPU0_SA_RSP<1>")
	)
	(segment
		(start 329.83932 -251.262134)
		(end 327.23328 -248.656094)
		(width 0.18288)
		(layer "In6.Cu")
		(net "M_B_CPU0_SA_RSP<1>")
	)
	(segment
		(start 312.344308 -248.992898)
		(end 312.00598 -248.65457)
		(width 0.18288)
		(layer "In6.Cu")
		(net "M_B_CPU0_SA_RSP<1>")
	)
	(segment
		(start 308.941724 -250.119896)
		(end 308.616604 -250.119896)
		(width 0.18288)
		(layer "In6.Cu")
		(net "M_B_CPU0_SA_RSP<1>")
	)
	(segment
		(start 346.533216 -253.919736)
		(end 346.532962 -253.032006)
		(width 0.088646)
		(layer "In6.Cu")
		(net "M_B_CPU0_SA_RSP<1>")
	)
	(segment
		(start 298.062396 -246.191024)
		(end 297.179238 -245.307866)
		(width 0.18288)
		(layer "In6.Cu")
		(net "M_B_CPU0_SA_RSP<1>")
	)
	(segment
		(start 323.59727 -248.656094)
		(end 320.897758 -251.355606)
		(width 0.18288)
		(layer "In6.Cu")
		(net "M_B_CPU0_SA_RSP<1>")
	)
	(segment
		(start 302.972724 -247.672606)
		(end 302.789844 -247.489726)
		(width 0.18288)
		(layer "In6.Cu")
		(net "M_B_CPU0_SA_RSP<1>")
	)
	(segment
		(start 311.211722 -248.65457)
		(end 310.398668 -249.467624)
		(width 0.18288)
		(layer "In6.Cu")
		(net "M_B_CPU0_SA_RSP<1>")
	)
	(segment
		(start 302.281844 -247.0658)
		(end 302.098964 -247.24868)
		(width 0.18288)
		(layer "In6.Cu")
		(net "M_B_CPU0_SA_RSP<1>")
	)
	(segment
		(start 309.124604 -249.937016)
		(end 308.941724 -250.119896)
		(width 0.18288)
		(layer "In6.Cu")
		(net "M_B_CPU0_SA_RSP<1>")
	)
	(segment
		(start 302.098964 -247.489726)
		(end 301.916084 -247.672606)
		(width 0.18288)
		(layer "In6.Cu")
		(net "M_B_CPU0_SA_RSP<1>")
	)
	(segment
		(start 307.559964 -249.467624)
		(end 307.202332 -249.109992)
		(width 0.18288)
		(layer "In6.Cu")
		(net "M_B_CPU0_SA_RSP<1>")
	)
	(segment
		(start 303.676812 -247.915938)
		(end 303.43348 -247.672606)
		(width 0.18288)
		(layer "In6.Cu")
		(net "M_B_CPU0_SA_RSP<1>")
	)
	(segment
		(start 308.433724 -249.937016)
		(end 308.433724 -249.650504)
		(width 0.18288)
		(layer "In6.Cu")
		(net "M_B_CPU0_SA_RSP<1>")
	)
	(segment
		(start 306.851304 -247.915938)
		(end 305.812698 -247.915938)
		(width 0.18288)
		(layer "In6.Cu")
		(net "M_B_CPU0_SA_RSP<1>")
	)
	(segment
		(start 335.746852 -251.262134)
		(end 329.83932 -251.262134)
		(width 0.18288)
		(layer "In6.Cu")
		(net "M_B_CPU0_SA_RSP<1>")
	)
	(segment
		(start 303.43348 -247.672606)
		(end 302.972724 -247.672606)
		(width 0.18288)
		(layer "In6.Cu")
		(net "M_B_CPU0_SA_RSP<1>")
	)
	(segment
		(start 302.098964 -247.24868)
		(end 302.098964 -247.489726)
		(width 0.18288)
		(layer "In6.Cu")
		(net "M_B_CPU0_SA_RSP<1>")
	)
	(segment
		(start 296.145712 -245.307866)
		(end 294.904414 -244.066568)
		(width 0.18288)
		(layer "In6.Cu")
		(net "M_B_CPU0_SA_RSP<1>")
	)
	(segment
		(start 305.629818 -248.098818)
		(end 305.629818 -248.92381)
		(width 0.18288)
		(layer "In6.Cu")
		(net "M_B_CPU0_SA_RSP<1>")
	)
	(segment
		(start 287.360614 -244.066568)
		(end 286.255714 -244.066568)
		(width 0.20066)
		(layer "F.Cu")
		(net "M_B_CPU0_SA_RSP<0>")
	)
	(segment
		(start 347.003116 -254.197612)
		(end 347.003116 -254.733298)
		(width 0.20066)
		(layer "F.Cu")
		(net "M_B_CPU0_SA_RSP<0>")
	)
	(segment
		(start 347.003116 -254.733298)
		(end 347.002862 -254.733552)
		(width 0.20066)
		(layer "F.Cu")
		(net "M_B_CPU0_SA_RSP<0>")
	)
	(segment
		(start 311.13222 -250.354084)
		(end 310.321452 -251.164852)
		(width 0.18288)
		(layer "In6.Cu")
		(net "M_B_CPU0_SA_RSP<0>")
	)
	(segment
		(start 299.257974 -247.891046)
		(end 298.668694 -247.891046)
		(width 0.18288)
		(layer "In6.Cu")
		(net "M_B_CPU0_SA_RSP<0>")
	)
	(segment
		(start 313.644026 -251.22632)
		(end 313.003946 -250.58624)
		(width 0.18288)
		(layer "In6.Cu")
		(net "M_B_CPU0_SA_RSP<0>")
	)
	(segment
		(start 335.964022 -252.49632)
		(end 335.400904 -251.933202)
		(width 0.18288)
		(layer "In6.Cu")
		(net "M_B_CPU0_SA_RSP<0>")
	)
	(segment
		(start 299.588174 -248.221246)
		(end 299.257974 -247.891046)
		(width 0.18288)
		(layer "In6.Cu")
		(net "M_B_CPU0_SA_RSP<0>")
	)
	(segment
		(start 296.184066 -246.648478)
		(end 295.312338 -246.191024)
		(width 0.18288)
		(layer "In6.Cu")
		(net "M_B_CPU0_SA_RSP<0>")
	)
	(segment
		(start 316.57925 -252.441964)
		(end 313.644026 -251.22632)
		(width 0.18288)
		(layer "In6.Cu")
		(net "M_B_CPU0_SA_RSP<0>")
	)
	(segment
		(start 346.077032 -254.255016)
		(end 346.042996 -254.202692)
		(width 0.088646)
		(layer "In6.Cu")
		(net "M_B_CPU0_SA_RSP<0>")
	)
	(segment
		(start 346.042996 -254.202692)
		(end 346.014802 -254.147066)
		(width 0.088646)
		(layer "In6.Cu")
		(net "M_B_CPU0_SA_RSP<0>")
	)
	(segment
		(start 345.468448 -253.06528)
		(end 345.468448 -252.781308)
		(width 0.088646)
		(layer "In6.Cu")
		(net "M_B_CPU0_SA_RSP<0>")
	)
	(segment
		(start 345.32824 -252.49632)
		(end 335.964022 -252.49632)
		(width 0.18288)
		(layer "In6.Cu")
		(net "M_B_CPU0_SA_RSP<0>")
	)
	(segment
		(start 326.954388 -249.327162)
		(end 324.334378 -249.327162)
		(width 0.18288)
		(layer "In6.Cu")
		(net "M_B_CPU0_SA_RSP<0>")
	)
	(segment
		(start 346.116656 -254.303276)
		(end 346.077032 -254.255016)
		(width 0.088646)
		(layer "In6.Cu")
		(net "M_B_CPU0_SA_RSP<0>")
	)
	(segment
		(start 346.270072 -254.420116)
		(end 346.244418 -254.405638)
		(width 0.088646)
		(layer "In6.Cu")
		(net "M_B_CPU0_SA_RSP<0>")
	)
	(segment
		(start 312.443622 -250.354084)
		(end 311.13222 -250.354084)
		(width 0.18288)
		(layer "In6.Cu")
		(net "M_B_CPU0_SA_RSP<0>")
	)
	(segment
		(start 346.16136 -254.34671)
		(end 346.116656 -254.303276)
		(width 0.088646)
		(layer "In6.Cu")
		(net "M_B_CPU0_SA_RSP<0>")
	)
	(segment
		(start 324.334378 -249.327162)
		(end 321.219576 -252.441964)
		(width 0.18288)
		(layer "In6.Cu")
		(net "M_B_CPU0_SA_RSP<0>")
	)
	(segment
		(start 321.219576 -252.441964)
		(end 316.57925 -252.441964)
		(width 0.18288)
		(layer "In6.Cu")
		(net "M_B_CPU0_SA_RSP<0>")
	)
	(segment
		(start 303.30267 -250.182126)
		(end 302.6156 -249.495056)
		(width 0.18288)
		(layer "In6.Cu")
		(net "M_B_CPU0_SA_RSP<0>")
	)
	(segment
		(start 302.6156 -249.495056)
		(end 300.43501 -248.945146)
		(width 0.18288)
		(layer "In6.Cu")
		(net "M_B_CPU0_SA_RSP<0>")
	)
	(segment
		(start 346.244418 -254.405638)
		(end 346.210636 -254.38481)
		(width 0.088646)
		(layer "In6.Cu")
		(net "M_B_CPU0_SA_RSP<0>")
	)
	(segment
		(start 347.002862 -254.733552)
		(end 346.30614 -254.438658)
		(width 0.088646)
		(layer "In6.Cu")
		(net "M_B_CPU0_SA_RSP<0>")
	)
	(segment
		(start 313.003946 -250.58624)
		(end 312.443622 -250.354084)
		(width 0.18288)
		(layer "In6.Cu")
		(net "M_B_CPU0_SA_RSP<0>")
	)
	(segment
		(start 346.30614 -254.438658)
		(end 346.270072 -254.420116)
		(width 0.088646)
		(layer "In6.Cu")
		(net "M_B_CPU0_SA_RSP<0>")
	)
	(segment
		(start 329.560428 -251.933202)
		(end 326.954388 -249.327162)
		(width 0.18288)
		(layer "In6.Cu")
		(net "M_B_CPU0_SA_RSP<0>")
	)
	(segment
		(start 345.992958 -254.088646)
		(end 345.977718 -254.028448)
		(width 0.088646)
		(layer "In6.Cu")
		(net "M_B_CPU0_SA_RSP<0>")
	)
	(segment
		(start 346.210636 -254.38481)
		(end 346.16136 -254.34671)
		(width 0.088646)
		(layer "In6.Cu")
		(net "M_B_CPU0_SA_RSP<0>")
	)
	(segment
		(start 345.968066 -253.564898)
		(end 345.468448 -253.06528)
		(width 0.088646)
		(layer "In6.Cu")
		(net "M_B_CPU0_SA_RSP<0>")
	)
	(segment
		(start 346.014802 -254.147066)
		(end 345.992958 -254.088646)
		(width 0.088646)
		(layer "In6.Cu")
		(net "M_B_CPU0_SA_RSP<0>")
	)
	(segment
		(start 345.468448 -252.781308)
		(end 345.468448 -252.636528)
		(width 0.18288)
		(layer "In6.Cu")
		(net "M_B_CPU0_SA_RSP<0>")
	)
	(segment
		(start 300.43501 -248.945146)
		(end 299.938694 -248.792746)
		(width 0.18288)
		(layer "In6.Cu")
		(net "M_B_CPU0_SA_RSP<0>")
	)
	(segment
		(start 290.950142 -246.191024)
		(end 290.455096 -245.695978)
		(width 0.18288)
		(layer "In6.Cu")
		(net "M_B_CPU0_SA_RSP<0>")
	)
	(segment
		(start 335.400904 -251.933202)
		(end 329.560428 -251.933202)
		(width 0.18288)
		(layer "In6.Cu")
		(net "M_B_CPU0_SA_RSP<0>")
	)
	(segment
		(start 345.968066 -253.92761)
		(end 345.968066 -253.564898)
		(width 0.088646)
		(layer "In6.Cu")
		(net "M_B_CPU0_SA_RSP<0>")
	)
	(segment
		(start 307.48224 -251.164852)
		(end 306.499514 -250.182126)
		(width 0.18288)
		(layer "In6.Cu")
		(net "M_B_CPU0_SA_RSP<0>")
	)
	(segment
		(start 345.468448 -252.636528)
		(end 345.32824 -252.49632)
		(width 0.18288)
		(layer "In6.Cu")
		(net "M_B_CPU0_SA_RSP<0>")
	)
	(segment
		(start 310.321452 -251.164852)
		(end 307.48224 -251.164852)
		(width 0.18288)
		(layer "In6.Cu")
		(net "M_B_CPU0_SA_RSP<0>")
	)
	(segment
		(start 287.954466 -244.66042)
		(end 287.360614 -244.066568)
		(width 0.18288)
		(layer "In6.Cu")
		(net "M_B_CPU0_SA_RSP<0>")
	)
	(segment
		(start 290.455096 -245.695978)
		(end 287.954466 -244.66042)
		(width 0.18288)
		(layer "In6.Cu")
		(net "M_B_CPU0_SA_RSP<0>")
	)
	(segment
		(start 299.588174 -248.442226)
		(end 299.588174 -248.221246)
		(width 0.18288)
		(layer "In6.Cu")
		(net "M_B_CPU0_SA_RSP<0>")
	)
	(segment
		(start 295.312338 -246.191024)
		(end 290.950142 -246.191024)
		(width 0.18288)
		(layer "In6.Cu")
		(net "M_B_CPU0_SA_RSP<0>")
	)
	(segment
		(start 345.977718 -254.028448)
		(end 345.969082 -253.966472)
		(width 0.088646)
		(layer "In6.Cu")
		(net "M_B_CPU0_SA_RSP<0>")
	)
	(segment
		(start 306.499514 -250.182126)
		(end 303.30267 -250.182126)
		(width 0.18288)
		(layer "In6.Cu")
		(net "M_B_CPU0_SA_RSP<0>")
	)
	(segment
		(start 298.668694 -247.891046)
		(end 296.184066 -246.648478)
		(width 0.18288)
		(layer "In6.Cu")
		(net "M_B_CPU0_SA_RSP<0>")
	)
	(segment
		(start 299.938694 -248.792746)
		(end 299.588174 -248.442226)
		(width 0.18288)
		(layer "In6.Cu")
		(net "M_B_CPU0_SA_RSP<0>")
	)
	(segment
		(start 345.969082 -253.966472)
		(end 345.968066 -253.92761)
		(width 0.088646)
		(layer "In6.Cu")
		(net "M_B_CPU0_SA_RSP<0>")
	)
	(segment
		(start 288.600388 -258.955286)
		(end 288.46018 -259.095494)
		(width 0.20066)
		(layer "F.Cu")
		(net "M_B_CPU0_SA_PAR")
	)
	(segment
		(start 288.238946 -259.60578)
		(end 287.82899 -259.60578)
		(width 0.20066)
		(layer "F.Cu")
		(net "M_B_CPU0_SA_PAR")
	)
	(segment
		(start 341.254334 -248.528078)
		(end 341.25408 -248.527824)
		(width 0.20066)
		(layer "F.Cu")
		(net "M_B_CPU0_SA_PAR")
	)
	(segment
		(start 288.46018 -259.384546)
		(end 288.238946 -259.60578)
		(width 0.20066)
		(layer "F.Cu")
		(net "M_B_CPU0_SA_PAR")
	)
	(segment
		(start 292.093142 -259.366766)
		(end 291.6682 -258.941824)
		(width 0.20066)
		(layer "F.Cu")
		(net "M_B_CPU0_SA_PAR")
	)
	(segment
		(start 287.589976 -259.366766)
		(end 286.255714 -259.366766)
		(width 0.20066)
		(layer "F.Cu")
		(net "M_B_CPU0_SA_PAR")
	)
	(segment
		(start 287.82899 -259.60578)
		(end 287.589976 -259.366766)
		(width 0.20066)
		(layer "F.Cu")
		(net "M_B_CPU0_SA_PAR")
	)
	(segment
		(start 288.46018 -259.095494)
		(end 288.46018 -259.384546)
		(width 0.20066)
		(layer "F.Cu")
		(net "M_B_CPU0_SA_PAR")
	)
	(segment
		(start 289.25393 -258.941824)
		(end 289.240214 -258.95554)
		(width 0.101854)
		(layer "F.Cu")
		(net "M_B_CPU0_SA_PAR")
	)
	(segment
		(start 289.240214 -258.95554)
		(end 289.231578 -258.95554)
		(width 0.101854)
		(layer "F.Cu")
		(net "M_B_CPU0_SA_PAR")
	)
	(segment
		(start 289.231578 -258.95554)
		(end 288.600642 -258.95554)
		(width 0.20066)
		(layer "F.Cu")
		(net "M_B_CPU0_SA_PAR")
	)
	(segment
		(start 291.556694 -258.941824)
		(end 291.225986 -258.941824)
		(width 0.101854)
		(layer "F.Cu")
		(net "M_B_CPU0_SA_PAR")
	)
	(segment
		(start 291.225986 -258.941824)
		(end 289.25393 -258.941824)
		(width 0.1016)
		(layer "F.Cu")
		(net "M_B_CPU0_SA_PAR")
	)
	(segment
		(start 288.600642 -258.95554)
		(end 288.600388 -258.955286)
		(width 0.20066)
		(layer "F.Cu")
		(net "M_B_CPU0_SA_PAR")
	)
	(segment
		(start 293.799514 -259.366766)
		(end 292.093142 -259.366766)
		(width 0.20066)
		(layer "F.Cu")
		(net "M_B_CPU0_SA_PAR")
	)
	(segment
		(start 341.25408 -248.527824)
		(end 341.25408 -247.992138)
		(width 0.20066)
		(layer "F.Cu")
		(net "M_B_CPU0_SA_PAR")
	)
	(segment
		(start 291.6682 -258.941824)
		(end 291.556694 -258.941824)
		(width 0.20066)
		(layer "F.Cu")
		(net "M_B_CPU0_SA_PAR")
	)
	(segment
		(start 294.904414 -259.366766)
		(end 293.799514 -259.366766)
		(width 0.20066)
		(layer "F.Cu")
		(net "M_B_CPU0_SA_PAR")
	)
	(segment
		(start 307.195728 -257.051048)
		(end 301.520352 -258.265168)
		(width 0.18288)
		(layer "In2.Cu")
		(net "M_B_CPU0_SA_PAR")
	)
	(segment
		(start 341.25408 -247.992138)
		(end 341.349584 -248.77268)
		(width 0.088646)
		(layer "In2.Cu")
		(net "M_B_CPU0_SA_PAR")
	)
	(segment
		(start 312.756296 -257.051048)
		(end 307.195728 -257.051048)
		(width 0.18288)
		(layer "In2.Cu")
		(net "M_B_CPU0_SA_PAR")
	)
	(segment
		(start 342.56853 -249.620024)
		(end 342.568784 -249.620278)
		(width 0.088646)
		(layer "In2.Cu")
		(net "M_B_CPU0_SA_PAR")
	)
	(segment
		(start 342.427814 -250.663202)
		(end 341.808816 -251.2822)
		(width 0.18288)
		(layer "In2.Cu")
		(net "M_B_CPU0_SA_PAR")
	)
	(segment
		(start 301.520352 -258.265168)
		(end 300.65091 -258.846574)
		(width 0.18288)
		(layer "In2.Cu")
		(net "M_B_CPU0_SA_PAR")
	)
	(segment
		(start 339.847936 -252.094238)
		(end 334.908144 -252.094238)
		(width 0.18288)
		(layer "In2.Cu")
		(net "M_B_CPU0_SA_PAR")
	)
	(segment
		(start 300.406816 -259.08762)
		(end 300.149768 -259.696712)
		(width 0.18288)
		(layer "In2.Cu")
		(net "M_B_CPU0_SA_PAR")
	)
	(segment
		(start 299.544994 -260.44906)
		(end 299.352462 -260.641592)
		(width 0.18288)
		(layer "In2.Cu")
		(net "M_B_CPU0_SA_PAR")
	)
	(segment
		(start 342.427814 -250.114562)
		(end 342.427814 -250.663202)
		(width 0.18288)
		(layer "In2.Cu")
		(net "M_B_CPU0_SA_PAR")
	)
	(segment
		(start 330.7334 -252.256036)
		(end 327.43775 -255.551686)
		(width 0.18288)
		(layer "In2.Cu")
		(net "M_B_CPU0_SA_PAR")
	)
	(segment
		(start 300.65091 -258.846574)
		(end 300.406816 -259.08762)
		(width 0.18288)
		(layer "In2.Cu")
		(net "M_B_CPU0_SA_PAR")
	)
	(segment
		(start 334.517492 -252.256036)
		(end 330.7334 -252.256036)
		(width 0.18288)
		(layer "In2.Cu")
		(net "M_B_CPU0_SA_PAR")
	)
	(segment
		(start 341.349584 -248.77268)
		(end 341.349584 -248.806208)
		(width 0.088646)
		(layer "In2.Cu")
		(net "M_B_CPU0_SA_PAR")
	)
	(segment
		(start 342.568784 -249.620278)
		(end 342.568784 -249.78868)
		(width 0.088646)
		(layer "In2.Cu")
		(net "M_B_CPU0_SA_PAR")
	)
	(segment
		(start 341.536782 -249.130312)
		(end 341.82304 -249.295412)
		(width 0.088646)
		(layer "In2.Cu")
		(net "M_B_CPU0_SA_PAR")
	)
	(segment
		(start 297.106594 -260.641592)
		(end 296.366438 -260.336792)
		(width 0.18288)
		(layer "In2.Cu")
		(net "M_B_CPU0_SA_PAR")
	)
	(segment
		(start 318.819784 -255.925066)
		(end 312.756296 -257.051048)
		(width 0.18288)
		(layer "In2.Cu")
		(net "M_B_CPU0_SA_PAR")
	)
	(segment
		(start 300.149768 -259.696712)
		(end 299.877734 -259.965444)
		(width 0.18288)
		(layer "In2.Cu")
		(net "M_B_CPU0_SA_PAR")
	)
	(segment
		(start 299.352462 -260.641592)
		(end 297.106594 -260.641592)
		(width 0.18288)
		(layer "In2.Cu")
		(net "M_B_CPU0_SA_PAR")
	)
	(segment
		(start 341.808816 -251.2822)
		(end 339.847936 -252.094238)
		(width 0.18288)
		(layer "In2.Cu")
		(net "M_B_CPU0_SA_PAR")
	)
	(segment
		(start 327.43775 -255.551686)
		(end 319.790064 -255.551686)
		(width 0.18288)
		(layer "In2.Cu")
		(net "M_B_CPU0_SA_PAR")
	)
	(segment
		(start 342.006682 -249.295666)
		(end 342.006936 -249.295666)
		(width 0.088646)
		(layer "In2.Cu")
		(net "M_B_CPU0_SA_PAR")
	)
	(segment
		(start 342.568784 -249.78868)
		(end 342.427814 -249.92965)
		(width 0.088646)
		(layer "In2.Cu")
		(net "M_B_CPU0_SA_PAR")
	)
	(segment
		(start 342.427814 -249.92965)
		(end 342.427814 -250.114562)
		(width 0.088646)
		(layer "In2.Cu")
		(net "M_B_CPU0_SA_PAR")
	)
	(segment
		(start 299.877734 -259.965444)
		(end 299.544994 -260.44906)
		(width 0.18288)
		(layer "In2.Cu")
		(net "M_B_CPU0_SA_PAR")
	)
	(segment
		(start 334.908144 -252.094238)
		(end 334.517492 -252.256036)
		(width 0.18288)
		(layer "In2.Cu")
		(net "M_B_CPU0_SA_PAR")
	)
	(segment
		(start 296.366438 -260.336792)
		(end 294.904414 -259.366766)
		(width 0.18288)
		(layer "In2.Cu")
		(net "M_B_CPU0_SA_PAR")
	)
	(segment
		(start 342.381078 -249.295666)
		(end 342.381332 -249.29592)
		(width 0.088646)
		(layer "In2.Cu")
		(net "M_B_CPU0_SA_PAR")
	)
	(segment
		(start 319.415668 -255.695704)
		(end 318.819784 -255.925066)
		(width 0.18288)
		(layer "In2.Cu")
		(net "M_B_CPU0_SA_PAR")
	)
	(segment
		(start 319.790064 -255.551686)
		(end 319.415668 -255.695704)
		(width 0.18288)
		(layer "In2.Cu")
		(net "M_B_CPU0_SA_PAR")
	)
	(arc
		(start 341.82304 -249.295412)
		(mid 341.914815 -249.320083)
		(end 342.006682 -249.295666)
		(width 0.088646)
		(layer "In2.Cu")
		(net "M_B_CPU0_SA_PAR")
	)
	(arc
		(start 342.006936 -249.295666)
		(mid 342.194024 -249.245489)
		(end 342.381078 -249.295666)
		(width 0.088646)
		(layer "In2.Cu")
		(net "M_B_CPU0_SA_PAR")
	)
	(arc
		(start 341.349584 -248.806208)
		(mid 341.399748 -248.993346)
		(end 341.536782 -249.130312)
		(width 0.088646)
		(layer "In2.Cu")
		(net "M_B_CPU0_SA_PAR")
	)
	(arc
		(start 342.381332 -249.29592)
		(mid 342.518377 -249.43288)
		(end 342.56853 -249.620024)
		(width 0.088646)
		(layer "In2.Cu")
		(net "M_B_CPU0_SA_PAR")
	)
	(segment
		(start 299.029882 -273.816572)
		(end 297.899582 -273.816572)
		(width 0.20066)
		(layer "F.Cu")
		(net "M_B_CPU0_SA_DQS_DP<9>")
	)
	(segment
		(start 290.830254 -273.816572)
		(end 290.355782 -273.816572)
		(width 0.20066)
		(layer "F.Cu")
		(net "M_B_CPU0_SA_DQS_DP<9>")
	)
	(segment
		(start 297.899582 -273.816572)
		(end 297.40987 -273.816572)
		(width 0.20066)
		(layer "F.Cu")
		(net "M_B_CPU0_SA_DQS_DP<9>")
	)
	(segment
		(start 292.477952 -273.386042)
		(end 292.208458 -273.655536)
		(width 0.20066)
		(layer "F.Cu")
		(net "M_B_CPU0_SA_DQS_DP<9>")
	)
	(segment
		(start 291.848286 -273.655536)
		(end 291.425884 -274.077938)
		(width 0.20066)
		(layer "F.Cu")
		(net "M_B_CPU0_SA_DQS_DP<9>")
	)
	(segment
		(start 292.208458 -273.655536)
		(end 291.848286 -273.655536)
		(width 0.20066)
		(layer "F.Cu")
		(net "M_B_CPU0_SA_DQS_DP<9>")
	)
	(segment
		(start 295.000172 -273.39163)
		(end 292.922198 -273.39163)
		(width 0.1016)
		(layer "F.Cu")
		(net "M_B_CPU0_SA_DQS_DP<9>")
	)
	(segment
		(start 292.67531 -273.386042)
		(end 292.477952 -273.386042)
		(width 0.20066)
		(layer "F.Cu")
		(net "M_B_CPU0_SA_DQS_DP<9>")
	)
	(segment
		(start 296.543984 -274.077938)
		(end 295.907968 -273.652996)
		(width 0.20066)
		(layer "F.Cu")
		(net "M_B_CPU0_SA_DQS_DP<9>")
	)
	(segment
		(start 339.014816 -259.895086)
		(end 339.014816 -260.430772)
		(width 0.20066)
		(layer "F.Cu")
		(net "M_B_CPU0_SA_DQS_DP<9>")
	)
	(segment
		(start 295.907968 -273.652996)
		(end 295.403016 -273.652996)
		(width 0.20066)
		(layer "F.Cu")
		(net "M_B_CPU0_SA_DQS_DP<9>")
	)
	(segment
		(start 297.40987 -273.816572)
		(end 297.148504 -274.077938)
		(width 0.20066)
		(layer "F.Cu")
		(net "M_B_CPU0_SA_DQS_DP<9>")
	)
	(segment
		(start 297.148504 -274.077938)
		(end 296.543984 -274.077938)
		(width 0.20066)
		(layer "F.Cu")
		(net "M_B_CPU0_SA_DQS_DP<9>")
	)
	(segment
		(start 291.09162 -274.077938)
		(end 290.830254 -273.816572)
		(width 0.20066)
		(layer "F.Cu")
		(net "M_B_CPU0_SA_DQS_DP<9>")
	)
	(segment
		(start 295.141904 -273.391884)
		(end 295.000426 -273.391884)
		(width 0.20066)
		(layer "F.Cu")
		(net "M_B_CPU0_SA_DQS_DP<9>")
	)
	(segment
		(start 292.922198 -273.39163)
		(end 292.680898 -273.39163)
		(width 0.101854)
		(layer "F.Cu")
		(net "M_B_CPU0_SA_DQS_DP<9>")
	)
	(segment
		(start 292.680898 -273.39163)
		(end 292.67531 -273.386042)
		(width 0.101854)
		(layer "F.Cu")
		(net "M_B_CPU0_SA_DQS_DP<9>")
	)
	(segment
		(start 295.403016 -273.652996)
		(end 295.141904 -273.391884)
		(width 0.20066)
		(layer "F.Cu")
		(net "M_B_CPU0_SA_DQS_DP<9>")
	)
	(segment
		(start 291.425884 -274.077938)
		(end 291.09162 -274.077938)
		(width 0.20066)
		(layer "F.Cu")
		(net "M_B_CPU0_SA_DQS_DP<9>")
	)
	(segment
		(start 339.014562 -259.894832)
		(end 339.014816 -259.895086)
		(width 0.20066)
		(layer "F.Cu")
		(net "M_B_CPU0_SA_DQS_DP<9>")
	)
	(segment
		(start 295.000426 -273.391884)
		(end 295.000172 -273.39163)
		(width 0.1016)
		(layer "F.Cu")
		(net "M_B_CPU0_SA_DQS_DP<9>")
	)
	(segment
		(start 304.498502 -273.209004)
		(end 304.470308 -273.237198)
		(width 0.16002)
		(layer "In2.Cu")
		(net "M_B_CPU0_SA_DQS_DP<9>")
	)
	(segment
		(start 309.5371 -273.447002)
		(end 309.520844 -273.447002)
		(width 0.16002)
		(layer "In2.Cu")
		(net "M_B_CPU0_SA_DQS_DP<9>")
	)
	(segment
		(start 314.20435 -271.781524)
		(end 314.176156 -271.75333)
		(width 0.16002)
		(layer "In2.Cu")
		(net "M_B_CPU0_SA_DQS_DP<9>")
	)
	(segment
		(start 304.681636 -273.02587)
		(end 304.498502 -273.209004)
		(width 0.18288)
		(layer "In2.Cu")
		(net "M_B_CPU0_SA_DQS_DP<9>")
	)
	(segment
		(start 314.160408 -271.75333)
		(end 313.960256 -271.553178)
		(width 0.16002)
		(layer "In2.Cu")
		(net "M_B_CPU0_SA_DQS_DP<9>")
	)
	(segment
		(start 302.51654 -274.303236)
		(end 302.316388 -274.103084)
		(width 0.16002)
		(layer "In2.Cu")
		(net "M_B_CPU0_SA_DQS_DP<9>")
	)
	(segment
		(start 329.648312 -262.033766)
		(end 328.962766 -262.033766)
		(width 0.088646)
		(layer "In2.Cu")
		(net "M_B_CPU0_SA_DQS_DP<9>")
	)
	(segment
		(start 328.962766 -262.033766)
		(end 326.349614 -262.033766)
		(width 0.18288)
		(layer "In2.Cu")
		(net "M_B_CPU0_SA_DQS_DP<9>")
	)
	(segment
		(start 304.470308 -273.237198)
		(end 304.470308 -273.252946)
		(width 0.16002)
		(layer "In2.Cu")
		(net "M_B_CPU0_SA_DQS_DP<9>")
	)
	(segment
		(start 303.830482 -273.877024)
		(end 303.485042 -273.877024)
		(width 0.18288)
		(layer "In2.Cu")
		(net "M_B_CPU0_SA_DQS_DP<9>")
	)
	(segment
		(start 313.960256 -271.553178)
		(end 313.960256 -271.53743)
		(width 0.16002)
		(layer "In2.Cu")
		(net "M_B_CPU0_SA_DQS_DP<9>")
	)
	(segment
		(start 302.316388 -274.103084)
		(end 302.316388 -274.087336)
		(width 0.16002)
		(layer "In2.Cu")
		(net "M_B_CPU0_SA_DQS_DP<9>")
	)
	(segment
		(start 306.66055 -273.481292)
		(end 306.632356 -273.453098)
		(width 0.16002)
		(layer "In2.Cu")
		(net "M_B_CPU0_SA_DQS_DP<9>")
	)
	(segment
		(start 302.288194 -274.059142)
		(end 302.105822 -273.87677)
		(width 0.18288)
		(layer "In2.Cu")
		(net "M_B_CPU0_SA_DQS_DP<9>")
	)
	(segment
		(start 307.11775 -273.661632)
		(end 306.84089 -273.661632)
		(width 0.18288)
		(layer "In2.Cu")
		(net "M_B_CPU0_SA_DQS_DP<9>")
	)
	(segment
		(start 321.875912 -264.663682)
		(end 314.651136 -271.88541)
		(width 0.18288)
		(layer "In2.Cu")
		(net "M_B_CPU0_SA_DQS_DP<9>")
	)
	(segment
		(start 306.388262 -273.209004)
		(end 306.205128 -273.02587)
		(width 0.18288)
		(layer "In2.Cu")
		(net "M_B_CPU0_SA_DQS_DP<9>")
	)
	(segment
		(start 304.226214 -273.481292)
		(end 303.830482 -273.877024)
		(width 0.18288)
		(layer "In2.Cu")
		(net "M_B_CPU0_SA_DQS_DP<9>")
	)
	(segment
		(start 299.870622 -274.36699)
		(end 299.500798 -273.997166)
		(width 0.18288)
		(layer "In2.Cu")
		(net "M_B_CPU0_SA_DQS_DP<9>")
	)
	(segment
		(start 337.417664 -259.941314)
		(end 337.402932 -259.932678)
		(width 0.088646)
		(layer "In2.Cu")
		(net "M_B_CPU0_SA_DQS_DP<9>")
	)
	(segment
		(start 302.316388 -274.087336)
		(end 302.288194 -274.059142)
		(width 0.16002)
		(layer "In2.Cu")
		(net "M_B_CPU0_SA_DQS_DP<9>")
	)
	(segment
		(start 309.49265 -273.475196)
		(end 309.306214 -273.661632)
		(width 0.18288)
		(layer "In2.Cu")
		(net "M_B_CPU0_SA_DQS_DP<9>")
	)
	(segment
		(start 331.690218 -259.99186)
		(end 329.648312 -262.033766)
		(width 0.088646)
		(layer "In2.Cu")
		(net "M_B_CPU0_SA_DQS_DP<9>")
	)
	(segment
		(start 300.580806 -273.87677)
		(end 300.398434 -274.059142)
		(width 0.18288)
		(layer "In2.Cu")
		(net "M_B_CPU0_SA_DQS_DP<9>")
	)
	(segment
		(start 314.651136 -271.88541)
		(end 314.308236 -271.88541)
		(width 0.18288)
		(layer "In2.Cu")
		(net "M_B_CPU0_SA_DQS_DP<9>")
	)
	(segment
		(start 306.416456 -273.252946)
		(end 306.416456 -273.237198)
		(width 0.16002)
		(layer "In2.Cu")
		(net "M_B_CPU0_SA_DQS_DP<9>")
	)
	(segment
		(start 299.210476 -273.997166)
		(end 299.029882 -273.816572)
		(width 0.18288)
		(layer "In2.Cu")
		(net "M_B_CPU0_SA_DQS_DP<9>")
	)
	(segment
		(start 302.934116 -274.42795)
		(end 302.657002 -274.42795)
		(width 0.18288)
		(layer "In2.Cu")
		(net "M_B_CPU0_SA_DQS_DP<9>")
	)
	(segment
		(start 338.701888 -260.430772)
		(end 338.636356 -260.36524)
		(width 0.088646)
		(layer "In2.Cu")
		(net "M_B_CPU0_SA_DQS_DP<9>")
	)
	(segment
		(start 308.014878 -273.661632)
		(end 307.743098 -273.389852)
		(width 0.18288)
		(layer "In2.Cu")
		(net "M_B_CPU0_SA_DQS_DP<9>")
	)
	(segment
		(start 338.36356 -259.94487)
		(end 338.342224 -259.932678)
		(width 0.088646)
		(layer "In2.Cu")
		(net "M_B_CPU0_SA_DQS_DP<9>")
	)
	(segment
		(start 314.176156 -271.75333)
		(end 314.160408 -271.75333)
		(width 0.16002)
		(layer "In2.Cu")
		(net "M_B_CPU0_SA_DQS_DP<9>")
	)
	(segment
		(start 304.470308 -273.252946)
		(end 304.270156 -273.453098)
		(width 0.16002)
		(layer "In2.Cu")
		(net "M_B_CPU0_SA_DQS_DP<9>")
	)
	(segment
		(start 312.225436 -271.326102)
		(end 312.042302 -271.509236)
		(width 0.18288)
		(layer "In2.Cu")
		(net "M_B_CPU0_SA_DQS_DP<9>")
	)
	(segment
		(start 313.748928 -271.326102)
		(end 312.225436 -271.326102)
		(width 0.18288)
		(layer "In2.Cu")
		(net "M_B_CPU0_SA_DQS_DP<9>")
	)
	(segment
		(start 306.205128 -273.02587)
		(end 304.681636 -273.02587)
		(width 0.18288)
		(layer "In2.Cu")
		(net "M_B_CPU0_SA_DQS_DP<9>")
	)
	(segment
		(start 302.105822 -273.87677)
		(end 300.580806 -273.87677)
		(width 0.18288)
		(layer "In2.Cu")
		(net "M_B_CPU0_SA_DQS_DP<9>")
	)
	(segment
		(start 300.37024 -274.087336)
		(end 300.37024 -274.103084)
		(width 0.16002)
		(layer "In2.Cu")
		(net "M_B_CPU0_SA_DQS_DP<9>")
	)
	(segment
		(start 309.764938 -273.202908)
		(end 309.736744 -273.231102)
		(width 0.16002)
		(layer "In2.Cu")
		(net "M_B_CPU0_SA_DQS_DP<9>")
	)
	(segment
		(start 311.813956 -271.75333)
		(end 311.798208 -271.75333)
		(width 0.16002)
		(layer "In2.Cu")
		(net "M_B_CPU0_SA_DQS_DP<9>")
	)
	(segment
		(start 306.616608 -273.453098)
		(end 306.416456 -273.252946)
		(width 0.16002)
		(layer "In2.Cu")
		(net "M_B_CPU0_SA_DQS_DP<9>")
	)
	(segment
		(start 339.014816 -260.430772)
		(end 338.701888 -260.430772)
		(width 0.088646)
		(layer "In2.Cu")
		(net "M_B_CPU0_SA_DQS_DP<9>")
	)
	(segment
		(start 307.743098 -273.389852)
		(end 307.38953 -273.389852)
		(width 0.18288)
		(layer "In2.Cu")
		(net "M_B_CPU0_SA_DQS_DP<9>")
	)
	(segment
		(start 307.38953 -273.389852)
		(end 307.11775 -273.661632)
		(width 0.18288)
		(layer "In2.Cu")
		(net "M_B_CPU0_SA_DQS_DP<9>")
	)
	(segment
		(start 309.306214 -273.661632)
		(end 308.014878 -273.661632)
		(width 0.18288)
		(layer "In2.Cu")
		(net "M_B_CPU0_SA_DQS_DP<9>")
	)
	(segment
		(start 300.398434 -274.059142)
		(end 300.37024 -274.087336)
		(width 0.16002)
		(layer "In2.Cu")
		(net "M_B_CPU0_SA_DQS_DP<9>")
	)
	(segment
		(start 311.798208 -271.75333)
		(end 311.770014 -271.781524)
		(width 0.16002)
		(layer "In2.Cu")
		(net "M_B_CPU0_SA_DQS_DP<9>")
	)
	(segment
		(start 304.270156 -273.453098)
		(end 304.254408 -273.453098)
		(width 0.16002)
		(layer "In2.Cu")
		(net "M_B_CPU0_SA_DQS_DP<9>")
	)
	(segment
		(start 338.342224 -259.932678)
		(end 338.342732 -259.932678)
		(width 0.088646)
		(layer "In2.Cu")
		(net "M_B_CPU0_SA_DQS_DP<9>")
	)
	(segment
		(start 302.657002 -274.42795)
		(end 302.560482 -274.33143)
		(width 0.18288)
		(layer "In2.Cu")
		(net "M_B_CPU0_SA_DQS_DP<9>")
	)
	(segment
		(start 313.932062 -271.509236)
		(end 313.748928 -271.326102)
		(width 0.18288)
		(layer "In2.Cu")
		(net "M_B_CPU0_SA_DQS_DP<9>")
	)
	(segment
		(start 314.308236 -271.88541)
		(end 314.20435 -271.781524)
		(width 0.18288)
		(layer "In2.Cu")
		(net "M_B_CPU0_SA_DQS_DP<9>")
	)
	(segment
		(start 302.532288 -274.303236)
		(end 302.51654 -274.303236)
		(width 0.16002)
		(layer "In2.Cu")
		(net "M_B_CPU0_SA_DQS_DP<9>")
	)
	(segment
		(start 304.254408 -273.453098)
		(end 304.226214 -273.481292)
		(width 0.16002)
		(layer "In2.Cu")
		(net "M_B_CPU0_SA_DQS_DP<9>")
	)
	(segment
		(start 310.503316 -272.46453)
		(end 309.764938 -273.202908)
		(width 0.18288)
		(layer "In2.Cu")
		(net "M_B_CPU0_SA_DQS_DP<9>")
	)
	(segment
		(start 312.014108 -271.553178)
		(end 311.813956 -271.75333)
		(width 0.16002)
		(layer "In2.Cu")
		(net "M_B_CPU0_SA_DQS_DP<9>")
	)
	(segment
		(start 303.485042 -273.877024)
		(end 302.934116 -274.42795)
		(width 0.18288)
		(layer "In2.Cu")
		(net "M_B_CPU0_SA_DQS_DP<9>")
	)
	(segment
		(start 325.030846 -263.352534)
		(end 321.875912 -264.663682)
		(width 0.18288)
		(layer "In2.Cu")
		(net "M_B_CPU0_SA_DQS_DP<9>")
	)
	(segment
		(start 306.632356 -273.453098)
		(end 306.616608 -273.453098)
		(width 0.16002)
		(layer "In2.Cu")
		(net "M_B_CPU0_SA_DQS_DP<9>")
	)
	(segment
		(start 331.966062 -259.99186)
		(end 331.690218 -259.99186)
		(width 0.088646)
		(layer "In2.Cu")
		(net "M_B_CPU0_SA_DQS_DP<9>")
	)
	(segment
		(start 300.15434 -274.303236)
		(end 300.126146 -274.33143)
		(width 0.16002)
		(layer "In2.Cu")
		(net "M_B_CPU0_SA_DQS_DP<9>")
	)
	(segment
		(start 309.520844 -273.447002)
		(end 309.49265 -273.475196)
		(width 0.16002)
		(layer "In2.Cu")
		(net "M_B_CPU0_SA_DQS_DP<9>")
	)
	(segment
		(start 311.087008 -272.46453)
		(end 310.503316 -272.46453)
		(width 0.18288)
		(layer "In2.Cu")
		(net "M_B_CPU0_SA_DQS_DP<9>")
	)
	(segment
		(start 312.014108 -271.53743)
		(end 312.014108 -271.553178)
		(width 0.16002)
		(layer "In2.Cu")
		(net "M_B_CPU0_SA_DQS_DP<9>")
	)
	(segment
		(start 309.736744 -273.247358)
		(end 309.5371 -273.447002)
		(width 0.16002)
		(layer "In2.Cu")
		(net "M_B_CPU0_SA_DQS_DP<9>")
	)
	(segment
		(start 311.770014 -271.781524)
		(end 311.087008 -272.46453)
		(width 0.18288)
		(layer "In2.Cu")
		(net "M_B_CPU0_SA_DQS_DP<9>")
	)
	(segment
		(start 306.416456 -273.237198)
		(end 306.388262 -273.209004)
		(width 0.16002)
		(layer "In2.Cu")
		(net "M_B_CPU0_SA_DQS_DP<9>")
	)
	(segment
		(start 326.349614 -262.033766)
		(end 325.030846 -263.352534)
		(width 0.18288)
		(layer "In2.Cu")
		(net "M_B_CPU0_SA_DQS_DP<9>")
	)
	(segment
		(start 302.560482 -274.33143)
		(end 302.532288 -274.303236)
		(width 0.16002)
		(layer "In2.Cu")
		(net "M_B_CPU0_SA_DQS_DP<9>")
	)
	(segment
		(start 299.500798 -273.997166)
		(end 299.210476 -273.997166)
		(width 0.18288)
		(layer "In2.Cu")
		(net "M_B_CPU0_SA_DQS_DP<9>")
	)
	(segment
		(start 300.37024 -274.103084)
		(end 300.170088 -274.303236)
		(width 0.16002)
		(layer "In2.Cu")
		(net "M_B_CPU0_SA_DQS_DP<9>")
	)
	(segment
		(start 313.960256 -271.53743)
		(end 313.932062 -271.509236)
		(width 0.16002)
		(layer "In2.Cu")
		(net "M_B_CPU0_SA_DQS_DP<9>")
	)
	(segment
		(start 300.090586 -274.36699)
		(end 299.870622 -274.36699)
		(width 0.18288)
		(layer "In2.Cu")
		(net "M_B_CPU0_SA_DQS_DP<9>")
	)
	(segment
		(start 300.170088 -274.303236)
		(end 300.15434 -274.303236)
		(width 0.16002)
		(layer "In2.Cu")
		(net "M_B_CPU0_SA_DQS_DP<9>")
	)
	(segment
		(start 300.126146 -274.33143)
		(end 300.090586 -274.36699)
		(width 0.18288)
		(layer "In2.Cu")
		(net "M_B_CPU0_SA_DQS_DP<9>")
	)
	(segment
		(start 312.042302 -271.509236)
		(end 312.014108 -271.53743)
		(width 0.16002)
		(layer "In2.Cu")
		(net "M_B_CPU0_SA_DQS_DP<9>")
	)
	(segment
		(start 306.84089 -273.661632)
		(end 306.66055 -273.481292)
		(width 0.18288)
		(layer "In2.Cu")
		(net "M_B_CPU0_SA_DQS_DP<9>")
	)
	(segment
		(start 309.736744 -273.231102)
		(end 309.736744 -273.247358)
		(width 0.16002)
		(layer "In2.Cu")
		(net "M_B_CPU0_SA_DQS_DP<9>")
	)
	(arc
		(start 335.538064 -259.941314)
		(mid 335.255362 -259.865538)
		(end 334.97266 -259.941314)
		(width 0.088646)
		(layer "In2.Cu")
		(net "M_B_CPU0_SA_DQS_DP<9>")
	)
	(arc
		(start 338.342732 -259.932678)
		(mid 338.066257 -259.865358)
		(end 337.79206 -259.941314)
		(width 0.088646)
		(layer "In2.Cu")
		(net "M_B_CPU0_SA_DQS_DP<9>")
	)
	(arc
		(start 336.85226 -259.941314)
		(mid 336.665062 -259.991457)
		(end 336.477864 -259.941314)
		(width 0.088646)
		(layer "In2.Cu")
		(net "M_B_CPU0_SA_DQS_DP<9>")
	)
	(arc
		(start 336.477864 -259.941314)
		(mid 336.195162 -259.865538)
		(end 335.91246 -259.941314)
		(width 0.088646)
		(layer "In2.Cu")
		(net "M_B_CPU0_SA_DQS_DP<9>")
	)
	(arc
		(start 334.97266 -259.941314)
		(mid 334.785462 -259.991457)
		(end 334.598264 -259.941314)
		(width 0.088646)
		(layer "In2.Cu")
		(net "M_B_CPU0_SA_DQS_DP<9>")
	)
	(arc
		(start 337.79206 -259.941314)
		(mid 337.604862 -259.991457)
		(end 337.417664 -259.941314)
		(width 0.088646)
		(layer "In2.Cu")
		(net "M_B_CPU0_SA_DQS_DP<9>")
	)
	(arc
		(start 334.598264 -259.941314)
		(mid 334.315562 -259.865538)
		(end 334.03286 -259.941314)
		(width 0.088646)
		(layer "In2.Cu")
		(net "M_B_CPU0_SA_DQS_DP<9>")
	)
	(arc
		(start 333.658464 -259.941314)
		(mid 333.375762 -259.865538)
		(end 333.09306 -259.941314)
		(width 0.088646)
		(layer "In2.Cu")
		(net "M_B_CPU0_SA_DQS_DP<9>")
	)
	(arc
		(start 334.03286 -259.941314)
		(mid 333.845662 -259.991457)
		(end 333.658464 -259.941314)
		(width 0.088646)
		(layer "In2.Cu")
		(net "M_B_CPU0_SA_DQS_DP<9>")
	)
	(arc
		(start 338.636356 -260.36524)
		(mid 338.549112 -260.123152)
		(end 338.36356 -259.94487)
		(width 0.088646)
		(layer "In2.Cu")
		(net "M_B_CPU0_SA_DQS_DP<9>")
	)
	(arc
		(start 333.09306 -259.941314)
		(mid 332.905862 -259.991457)
		(end 332.718664 -259.941314)
		(width 0.088646)
		(layer "In2.Cu")
		(net "M_B_CPU0_SA_DQS_DP<9>")
	)
	(arc
		(start 332.15326 -259.941314)
		(mid 332.062984 -259.978888)
		(end 331.966062 -259.99186)
		(width 0.088646)
		(layer "In2.Cu")
		(net "M_B_CPU0_SA_DQS_DP<9>")
	)
	(arc
		(start 335.91246 -259.941314)
		(mid 335.725262 -259.991457)
		(end 335.538064 -259.941314)
		(width 0.088646)
		(layer "In2.Cu")
		(net "M_B_CPU0_SA_DQS_DP<9>")
	)
	(arc
		(start 332.718664 -259.941314)
		(mid 332.435962 -259.865538)
		(end 332.15326 -259.941314)
		(width 0.088646)
		(layer "In2.Cu")
		(net "M_B_CPU0_SA_DQS_DP<9>")
	)
	(arc
		(start 337.402932 -259.932678)
		(mid 337.126457 -259.865358)
		(end 336.85226 -259.941314)
		(width 0.088646)
		(layer "In2.Cu")
		(net "M_B_CPU0_SA_DQS_DP<9>")
	)
	(segment
		(start 295.403016 -283.00299)
		(end 295.907968 -283.00299)
		(width 0.20066)
		(layer "F.Cu")
		(net "M_B_CPU0_SA_DQS_DP<8>")
	)
	(segment
		(start 292.922198 -282.741624)
		(end 295.000172 -282.741624)
		(width 0.1016)
		(layer "F.Cu")
		(net "M_B_CPU0_SA_DQS_DP<8>")
	)
	(segment
		(start 291.848286 -283.00553)
		(end 292.208458 -283.00553)
		(width 0.20066)
		(layer "F.Cu")
		(net "M_B_CPU0_SA_DQS_DP<8>")
	)
	(segment
		(start 295.000426 -282.741878)
		(end 295.141904 -282.741878)
		(width 0.20066)
		(layer "F.Cu")
		(net "M_B_CPU0_SA_DQS_DP<8>")
	)
	(segment
		(start 292.477952 -282.736036)
		(end 292.67531 -282.736036)
		(width 0.20066)
		(layer "F.Cu")
		(net "M_B_CPU0_SA_DQS_DP<8>")
	)
	(segment
		(start 341.364316 -262.87222)
		(end 341.364062 -262.872474)
		(width 0.20066)
		(layer "F.Cu")
		(net "M_B_CPU0_SA_DQS_DP<8>")
	)
	(segment
		(start 297.40987 -283.166566)
		(end 297.899582 -283.166566)
		(width 0.20066)
		(layer "F.Cu")
		(net "M_B_CPU0_SA_DQS_DP<8>")
	)
	(segment
		(start 292.208458 -283.00553)
		(end 292.477952 -282.736036)
		(width 0.20066)
		(layer "F.Cu")
		(net "M_B_CPU0_SA_DQS_DP<8>")
	)
	(segment
		(start 291.09162 -283.427932)
		(end 291.425884 -283.427932)
		(width 0.20066)
		(layer "F.Cu")
		(net "M_B_CPU0_SA_DQS_DP<8>")
	)
	(segment
		(start 299.029882 -283.16682)
		(end 299.029628 -283.166566)
		(width 0.20066)
		(layer "F.Cu")
		(net "M_B_CPU0_SA_DQS_DP<8>")
	)
	(segment
		(start 295.000172 -282.741624)
		(end 295.000426 -282.741878)
		(width 0.1016)
		(layer "F.Cu")
		(net "M_B_CPU0_SA_DQS_DP<8>")
	)
	(segment
		(start 295.907968 -283.00299)
		(end 296.543984 -283.427932)
		(width 0.20066)
		(layer "F.Cu")
		(net "M_B_CPU0_SA_DQS_DP<8>")
	)
	(segment
		(start 292.67531 -282.736036)
		(end 292.680898 -282.741624)
		(width 0.101854)
		(layer "F.Cu")
		(net "M_B_CPU0_SA_DQS_DP<8>")
	)
	(segment
		(start 290.355782 -283.166566)
		(end 290.830254 -283.166566)
		(width 0.20066)
		(layer "F.Cu")
		(net "M_B_CPU0_SA_DQS_DP<8>")
	)
	(segment
		(start 296.543984 -283.427932)
		(end 297.148504 -283.427932)
		(width 0.20066)
		(layer "F.Cu")
		(net "M_B_CPU0_SA_DQS_DP<8>")
	)
	(segment
		(start 295.141904 -282.741878)
		(end 295.403016 -283.00299)
		(width 0.20066)
		(layer "F.Cu")
		(net "M_B_CPU0_SA_DQS_DP<8>")
	)
	(segment
		(start 297.148504 -283.427932)
		(end 297.40987 -283.166566)
		(width 0.20066)
		(layer "F.Cu")
		(net "M_B_CPU0_SA_DQS_DP<8>")
	)
	(segment
		(start 341.364316 -262.336534)
		(end 341.364316 -262.87222)
		(width 0.20066)
		(layer "F.Cu")
		(net "M_B_CPU0_SA_DQS_DP<8>")
	)
	(segment
		(start 290.830254 -283.166566)
		(end 291.09162 -283.427932)
		(width 0.20066)
		(layer "F.Cu")
		(net "M_B_CPU0_SA_DQS_DP<8>")
	)
	(segment
		(start 292.680898 -282.741624)
		(end 292.922198 -282.741624)
		(width 0.101854)
		(layer "F.Cu")
		(net "M_B_CPU0_SA_DQS_DP<8>")
	)
	(segment
		(start 299.029628 -283.166566)
		(end 297.899582 -283.166566)
		(width 0.20066)
		(layer "F.Cu")
		(net "M_B_CPU0_SA_DQS_DP<8>")
	)
	(segment
		(start 291.425884 -283.427932)
		(end 291.848286 -283.00553)
		(width 0.20066)
		(layer "F.Cu")
		(net "M_B_CPU0_SA_DQS_DP<8>")
	)
	(segment
		(start 323.45122 -265.12266)
		(end 323.45122 -265.298682)
		(width 0.18288)
		(layer "In4.Cu")
		(net "M_B_CPU0_SA_DQS_DP<8>")
	)
	(segment
		(start 336.951574 -262.385302)
		(end 336.948018 -262.383016)
		(width 0.088646)
		(layer "In4.Cu")
		(net "M_B_CPU0_SA_DQS_DP<8>")
	)
	(segment
		(start 311.271158 -275.046948)
		(end 310.598566 -276.670008)
		(width 0.18288)
		(layer "In4.Cu")
		(net "M_B_CPU0_SA_DQS_DP<8>")
	)
	(segment
		(start 321.547236 -267.026644)
		(end 321.547236 -267.202666)
		(width 0.18288)
		(layer "In4.Cu")
		(net "M_B_CPU0_SA_DQS_DP<8>")
	)
	(segment
		(start 323.063362 -265.68654)
		(end 322.88734 -265.68654)
		(width 0.18288)
		(layer "In4.Cu")
		(net "M_B_CPU0_SA_DQS_DP<8>")
	)
	(segment
		(start 330.724002 -262.46074)
		(end 327.609454 -262.46074)
		(width 0.18288)
		(layer "In4.Cu")
		(net "M_B_CPU0_SA_DQS_DP<8>")
	)
	(segment
		(start 319.255394 -269.494508)
		(end 319.079372 -269.494508)
		(width 0.18288)
		(layer "In4.Cu")
		(net "M_B_CPU0_SA_DQS_DP<8>")
	)
	(segment
		(start 324.9676 -263.782556)
		(end 324.791324 -263.782556)
		(width 0.18288)
		(layer "In4.Cu")
		(net "M_B_CPU0_SA_DQS_DP<8>")
	)
	(segment
		(start 325.355204 -263.394698)
		(end 324.9676 -263.782556)
		(width 0.18288)
		(layer "In4.Cu")
		(net "M_B_CPU0_SA_DQS_DP<8>")
	)
	(segment
		(start 339.773006 -262.386318)
		(end 339.761322 -262.379714)
		(width 0.088646)
		(layer "In4.Cu")
		(net "M_B_CPU0_SA_DQS_DP<8>")
	)
	(segment
		(start 324.403212 -264.34669)
		(end 324.015354 -264.734548)
		(width 0.18288)
		(layer "In4.Cu")
		(net "M_B_CPU0_SA_DQS_DP<8>")
	)
	(segment
		(start 327.609454 -262.46074)
		(end 325.355204 -263.394698)
		(width 0.18288)
		(layer "In4.Cu")
		(net "M_B_CPU0_SA_DQS_DP<8>")
	)
	(segment
		(start 324.015354 -264.734548)
		(end 323.839332 -264.734548)
		(width 0.18288)
		(layer "In4.Cu")
		(net "M_B_CPU0_SA_DQS_DP<8>")
	)
	(segment
		(start 313.413394 -273.847052)
		(end 312.90641 -274.056856)
		(width 0.18288)
		(layer "In4.Cu")
		(net "M_B_CPU0_SA_DQS_DP<8>")
	)
	(segment
		(start 302.56607 -281.979624)
		(end 301.761906 -282.312618)
		(width 0.18288)
		(layer "In4.Cu")
		(net "M_B_CPU0_SA_DQS_DP<8>")
	)
	(segment
		(start 320.595244 -268.154658)
		(end 320.207386 -268.542516)
		(width 0.18288)
		(layer "In4.Cu")
		(net "M_B_CPU0_SA_DQS_DP<8>")
	)
	(segment
		(start 306.203096 -279.579578)
		(end 304.24501 -279.579578)
		(width 0.18288)
		(layer "In4.Cu")
		(net "M_B_CPU0_SA_DQS_DP<8>")
	)
	(segment
		(start 300.326298 -283.591762)
		(end 299.93844 -283.591762)
		(width 0.18288)
		(layer "In4.Cu")
		(net "M_B_CPU0_SA_DQS_DP<8>")
	)
	(segment
		(start 318.69126 -270.058642)
		(end 318.303402 -270.4465)
		(width 0.18288)
		(layer "In4.Cu")
		(net "M_B_CPU0_SA_DQS_DP<8>")
	)
	(segment
		(start 309.03037 -277.82266)
		(end 308.854348 -277.82266)
		(width 0.18288)
		(layer "In4.Cu")
		(net "M_B_CPU0_SA_DQS_DP<8>")
	)
	(segment
		(start 320.207386 -268.542516)
		(end 320.031364 -268.542516)
		(width 0.18288)
		(layer "In4.Cu")
		(net "M_B_CPU0_SA_DQS_DP<8>")
	)
	(segment
		(start 316.787276 -271.786604)
		(end 316.787276 -271.962626)
		(width 0.18288)
		(layer "In4.Cu")
		(net "M_B_CPU0_SA_DQS_DP<8>")
	)
	(segment
		(start 315.72581 -273.024092)
		(end 313.576208 -273.914362)
		(width 0.18288)
		(layer "In4.Cu")
		(net "M_B_CPU0_SA_DQS_DP<8>")
	)
	(segment
		(start 340.759288 -262.41248)
		(end 340.701122 -262.379714)
		(width 0.088646)
		(layer "In4.Cu")
		(net "M_B_CPU0_SA_DQS_DP<8>")
	)
	(segment
		(start 341.364062 -262.872474)
		(end 341.359236 -262.867648)
		(width 0.088646)
		(layer "In4.Cu")
		(net "M_B_CPU0_SA_DQS_DP<8>")
	)
	(segment
		(start 324.791324 -263.782556)
		(end 324.403212 -264.170668)
		(width 0.18288)
		(layer "In4.Cu")
		(net "M_B_CPU0_SA_DQS_DP<8>")
	)
	(segment
		(start 317.739268 -271.010634)
		(end 317.35141 -271.398492)
		(width 0.18288)
		(layer "In4.Cu")
		(net "M_B_CPU0_SA_DQS_DP<8>")
	)
	(segment
		(start 310.238648 -277.029926)
		(end 309.529226 -277.323804)
		(width 0.18288)
		(layer "In4.Cu")
		(net "M_B_CPU0_SA_DQS_DP<8>")
	)
	(segment
		(start 319.643252 -269.10665)
		(end 319.255394 -269.494508)
		(width 0.18288)
		(layer "In4.Cu")
		(net "M_B_CPU0_SA_DQS_DP<8>")
	)
	(segment
		(start 308.03088 -278.82215)
		(end 306.203096 -279.579578)
		(width 0.18288)
		(layer "In4.Cu")
		(net "M_B_CPU0_SA_DQS_DP<8>")
	)
	(segment
		(start 336.392774 -262.37692)
		(end 336.38236 -262.383016)
		(width 0.088646)
		(layer "In4.Cu")
		(net "M_B_CPU0_SA_DQS_DP<8>")
	)
	(segment
		(start 319.643252 -268.930628)
		(end 319.643252 -269.10665)
		(width 0.18288)
		(layer "In4.Cu")
		(net "M_B_CPU0_SA_DQS_DP<8>")
	)
	(segment
		(start 323.839332 -264.734548)
		(end 323.45122 -265.12266)
		(width 0.18288)
		(layer "In4.Cu")
		(net "M_B_CPU0_SA_DQS_DP<8>")
	)
	(segment
		(start 303.307242 -280.517092)
		(end 302.796194 -281.7495)
		(width 0.18288)
		(layer "In4.Cu")
		(net "M_B_CPU0_SA_DQS_DP<8>")
	)
	(segment
		(start 312.8391 -274.21967)
		(end 311.574942 -274.743164)
		(width 0.18288)
		(layer "In4.Cu")
		(net "M_B_CPU0_SA_DQS_DP<8>")
	)
	(segment
		(start 312.90641 -274.056856)
		(end 312.8391 -274.21967)
		(width 0.18288)
		(layer "In4.Cu")
		(net "M_B_CPU0_SA_DQS_DP<8>")
	)
	(segment
		(start 308.854348 -277.82266)
		(end 308.465982 -278.211026)
		(width 0.18288)
		(layer "In4.Cu")
		(net "M_B_CPU0_SA_DQS_DP<8>")
	)
	(segment
		(start 330.820014 -262.52043)
		(end 330.760324 -262.46074)
		(width 0.088646)
		(layer "In4.Cu")
		(net "M_B_CPU0_SA_DQS_DP<8>")
	)
	(segment
		(start 310.598566 -276.670008)
		(end 310.238648 -277.029926)
		(width 0.18288)
		(layer "In4.Cu")
		(net "M_B_CPU0_SA_DQS_DP<8>")
	)
	(segment
		(start 299.300138 -283.437076)
		(end 299.029882 -283.16682)
		(width 0.18288)
		(layer "In4.Cu")
		(net "M_B_CPU0_SA_DQS_DP<8>")
	)
	(segment
		(start 320.983356 -267.590524)
		(end 320.595244 -267.978636)
		(width 0.18288)
		(layer "In4.Cu")
		(net "M_B_CPU0_SA_DQS_DP<8>")
	)
	(segment
		(start 319.079372 -269.494508)
		(end 318.69126 -269.88262)
		(width 0.18288)
		(layer "In4.Cu")
		(net "M_B_CPU0_SA_DQS_DP<8>")
	)
	(segment
		(start 331.496416 -262.433562)
		(end 331.240384 -262.433562)
		(width 0.088646)
		(layer "In4.Cu")
		(net "M_B_CPU0_SA_DQS_DP<8>")
	)
	(segment
		(start 299.783754 -283.437076)
		(end 299.300138 -283.437076)
		(width 0.18288)
		(layer "In4.Cu")
		(net "M_B_CPU0_SA_DQS_DP<8>")
	)
	(segment
		(start 304.24501 -279.579578)
		(end 303.307242 -280.517092)
		(width 0.18288)
		(layer "In4.Cu")
		(net "M_B_CPU0_SA_DQS_DP<8>")
	)
	(segment
		(start 331.68336 -262.383016)
		(end 331.683106 -262.38327)
		(width 0.088646)
		(layer "In4.Cu")
		(net "M_B_CPU0_SA_DQS_DP<8>")
	)
	(segment
		(start 300.593252 -283.481272)
		(end 300.326298 -283.591762)
		(width 0.18288)
		(layer "In4.Cu")
		(net "M_B_CPU0_SA_DQS_DP<8>")
	)
	(segment
		(start 337.891882 -262.385556)
		(end 337.887564 -262.383016)
		(width 0.088646)
		(layer "In4.Cu")
		(net "M_B_CPU0_SA_DQS_DP<8>")
	)
	(segment
		(start 318.303402 -270.4465)
		(end 318.12738 -270.4465)
		(width 0.18288)
		(layer "In4.Cu")
		(net "M_B_CPU0_SA_DQS_DP<8>")
	)
	(segment
		(start 308.465982 -278.387048)
		(end 308.03088 -278.82215)
		(width 0.18288)
		(layer "In4.Cu")
		(net "M_B_CPU0_SA_DQS_DP<8>")
	)
	(segment
		(start 302.796194 -281.7495)
		(end 302.56607 -281.979624)
		(width 0.18288)
		(layer "In4.Cu")
		(net "M_B_CPU0_SA_DQS_DP<8>")
	)
	(segment
		(start 301.761906 -282.312618)
		(end 300.593252 -283.481272)
		(width 0.18288)
		(layer "In4.Cu")
		(net "M_B_CPU0_SA_DQS_DP<8>")
	)
	(segment
		(start 321.547236 -267.202666)
		(end 321.159378 -267.590524)
		(width 0.18288)
		(layer "In4.Cu")
		(net "M_B_CPU0_SA_DQS_DP<8>")
	)
	(segment
		(start 311.574942 -274.743164)
		(end 311.271158 -275.046948)
		(width 0.18288)
		(layer "In4.Cu")
		(net "M_B_CPU0_SA_DQS_DP<8>")
	)
	(segment
		(start 322.88734 -265.68654)
		(end 322.499228 -266.074652)
		(width 0.18288)
		(layer "In4.Cu")
		(net "M_B_CPU0_SA_DQS_DP<8>")
	)
	(segment
		(start 317.175388 -271.398492)
		(end 316.787276 -271.786604)
		(width 0.18288)
		(layer "In4.Cu")
		(net "M_B_CPU0_SA_DQS_DP<8>")
	)
	(segment
		(start 317.35141 -271.398492)
		(end 317.175388 -271.398492)
		(width 0.18288)
		(layer "In4.Cu")
		(net "M_B_CPU0_SA_DQS_DP<8>")
	)
	(segment
		(start 320.595244 -267.978636)
		(end 320.595244 -268.154658)
		(width 0.18288)
		(layer "In4.Cu")
		(net "M_B_CPU0_SA_DQS_DP<8>")
	)
	(segment
		(start 323.45122 -265.298682)
		(end 323.063362 -265.68654)
		(width 0.18288)
		(layer "In4.Cu")
		(net "M_B_CPU0_SA_DQS_DP<8>")
	)
	(segment
		(start 320.031364 -268.542516)
		(end 319.643252 -268.930628)
		(width 0.18288)
		(layer "In4.Cu")
		(net "M_B_CPU0_SA_DQS_DP<8>")
	)
	(segment
		(start 331.153516 -262.52043)
		(end 330.820014 -262.52043)
		(width 0.088646)
		(layer "In4.Cu")
		(net "M_B_CPU0_SA_DQS_DP<8>")
	)
	(segment
		(start 321.935348 -266.638532)
		(end 321.547236 -267.026644)
		(width 0.18288)
		(layer "In4.Cu")
		(net "M_B_CPU0_SA_DQS_DP<8>")
	)
	(segment
		(start 309.529226 -277.323804)
		(end 309.03037 -277.82266)
		(width 0.18288)
		(layer "In4.Cu")
		(net "M_B_CPU0_SA_DQS_DP<8>")
	)
	(segment
		(start 324.403212 -264.170668)
		(end 324.403212 -264.34669)
		(width 0.18288)
		(layer "In4.Cu")
		(net "M_B_CPU0_SA_DQS_DP<8>")
	)
	(segment
		(start 338.833206 -262.386318)
		(end 338.821522 -262.379714)
		(width 0.088646)
		(layer "In4.Cu")
		(net "M_B_CPU0_SA_DQS_DP<8>")
	)
	(segment
		(start 322.499228 -266.074652)
		(end 322.499228 -266.250674)
		(width 0.18288)
		(layer "In4.Cu")
		(net "M_B_CPU0_SA_DQS_DP<8>")
	)
	(segment
		(start 317.739268 -270.834612)
		(end 317.739268 -271.010634)
		(width 0.18288)
		(layer "In4.Cu")
		(net "M_B_CPU0_SA_DQS_DP<8>")
	)
	(segment
		(start 330.760324 -262.46074)
		(end 330.724002 -262.46074)
		(width 0.088646)
		(layer "In4.Cu")
		(net "M_B_CPU0_SA_DQS_DP<8>")
	)
	(segment
		(start 322.11137 -266.638532)
		(end 321.935348 -266.638532)
		(width 0.18288)
		(layer "In4.Cu")
		(net "M_B_CPU0_SA_DQS_DP<8>")
	)
	(segment
		(start 318.12738 -270.4465)
		(end 317.739268 -270.834612)
		(width 0.18288)
		(layer "In4.Cu")
		(net "M_B_CPU0_SA_DQS_DP<8>")
	)
	(segment
		(start 321.159378 -267.590524)
		(end 320.983356 -267.590524)
		(width 0.18288)
		(layer "In4.Cu")
		(net "M_B_CPU0_SA_DQS_DP<8>")
	)
	(segment
		(start 313.576208 -273.914362)
		(end 313.413394 -273.847052)
		(width 0.18288)
		(layer "In4.Cu")
		(net "M_B_CPU0_SA_DQS_DP<8>")
	)
	(segment
		(start 308.465982 -278.211026)
		(end 308.465982 -278.387048)
		(width 0.18288)
		(layer "In4.Cu")
		(net "M_B_CPU0_SA_DQS_DP<8>")
	)
	(segment
		(start 316.787276 -271.962626)
		(end 315.72581 -273.024092)
		(width 0.18288)
		(layer "In4.Cu")
		(net "M_B_CPU0_SA_DQS_DP<8>")
	)
	(segment
		(start 331.240384 -262.433562)
		(end 331.153516 -262.52043)
		(width 0.088646)
		(layer "In4.Cu")
		(net "M_B_CPU0_SA_DQS_DP<8>")
	)
	(segment
		(start 322.499228 -266.250674)
		(end 322.11137 -266.638532)
		(width 0.18288)
		(layer "In4.Cu")
		(net "M_B_CPU0_SA_DQS_DP<8>")
	)
	(segment
		(start 299.93844 -283.591762)
		(end 299.783754 -283.437076)
		(width 0.18288)
		(layer "In4.Cu")
		(net "M_B_CPU0_SA_DQS_DP<8>")
	)
	(segment
		(start 318.69126 -269.88262)
		(end 318.69126 -270.058642)
		(width 0.18288)
		(layer "In4.Cu")
		(net "M_B_CPU0_SA_DQS_DP<8>")
	)
	(arc
		(start 331.683106 -262.38327)
		(mid 331.59306 -262.420656)
		(end 331.496416 -262.433562)
		(width 0.088646)
		(layer "In4.Cu")
		(net "M_B_CPU0_SA_DQS_DP<8>")
	)
	(arc
		(start 339.202014 -262.383016)
		(mid 339.01806 -262.433145)
		(end 338.833206 -262.386318)
		(width 0.088646)
		(layer "In4.Cu")
		(net "M_B_CPU0_SA_DQS_DP<8>")
	)
	(arc
		(start 337.322414 -262.383016)
		(mid 337.137293 -262.433279)
		(end 336.951574 -262.385302)
		(width 0.088646)
		(layer "In4.Cu")
		(net "M_B_CPU0_SA_DQS_DP<8>")
	)
	(arc
		(start 333.56296 -262.383016)
		(mid 333.375762 -262.433159)
		(end 333.188564 -262.383016)
		(width 0.088646)
		(layer "In4.Cu")
		(net "M_B_CPU0_SA_DQS_DP<8>")
	)
	(arc
		(start 335.068164 -262.383016)
		(mid 334.785462 -262.30724)
		(end 334.50276 -262.383016)
		(width 0.088646)
		(layer "In4.Cu")
		(net "M_B_CPU0_SA_DQS_DP<8>")
	)
	(arc
		(start 339.761322 -262.379714)
		(mid 339.481217 -262.307272)
		(end 339.202014 -262.383016)
		(width 0.088646)
		(layer "In4.Cu")
		(net "M_B_CPU0_SA_DQS_DP<8>")
	)
	(arc
		(start 338.262214 -262.383016)
		(mid 338.077377 -262.433277)
		(end 337.891882 -262.385556)
		(width 0.088646)
		(layer "In4.Cu")
		(net "M_B_CPU0_SA_DQS_DP<8>")
	)
	(arc
		(start 340.701122 -262.379714)
		(mid 340.421017 -262.307272)
		(end 340.141814 -262.383016)
		(width 0.088646)
		(layer "In4.Cu")
		(net "M_B_CPU0_SA_DQS_DP<8>")
	)
	(arc
		(start 336.38236 -262.383016)
		(mid 336.195162 -262.433159)
		(end 336.007964 -262.383016)
		(width 0.088646)
		(layer "In4.Cu")
		(net "M_B_CPU0_SA_DQS_DP<8>")
	)
	(arc
		(start 335.44256 -262.383016)
		(mid 335.255362 -262.433159)
		(end 335.068164 -262.383016)
		(width 0.088646)
		(layer "In4.Cu")
		(net "M_B_CPU0_SA_DQS_DP<8>")
	)
	(arc
		(start 332.62316 -262.383016)
		(mid 332.435962 -262.433159)
		(end 332.248764 -262.383016)
		(width 0.088646)
		(layer "In4.Cu")
		(net "M_B_CPU0_SA_DQS_DP<8>")
	)
	(arc
		(start 336.007964 -262.383016)
		(mid 335.725262 -262.30724)
		(end 335.44256 -262.383016)
		(width 0.088646)
		(layer "In4.Cu")
		(net "M_B_CPU0_SA_DQS_DP<8>")
	)
	(arc
		(start 332.248764 -262.383016)
		(mid 331.966062 -262.30724)
		(end 331.68336 -262.383016)
		(width 0.088646)
		(layer "In4.Cu")
		(net "M_B_CPU0_SA_DQS_DP<8>")
	)
	(arc
		(start 334.128364 -262.383016)
		(mid 333.845662 -262.30724)
		(end 333.56296 -262.383016)
		(width 0.088646)
		(layer "In4.Cu")
		(net "M_B_CPU0_SA_DQS_DP<8>")
	)
	(arc
		(start 334.50276 -262.383016)
		(mid 334.315562 -262.433159)
		(end 334.128364 -262.383016)
		(width 0.088646)
		(layer "In4.Cu")
		(net "M_B_CPU0_SA_DQS_DP<8>")
	)
	(arc
		(start 338.821522 -262.379714)
		(mid 338.541417 -262.307272)
		(end 338.262214 -262.383016)
		(width 0.088646)
		(layer "In4.Cu")
		(net "M_B_CPU0_SA_DQS_DP<8>")
	)
	(arc
		(start 341.359236 -262.867648)
		(mid 341.074815 -262.619563)
		(end 340.759288 -262.41248)
		(width 0.088646)
		(layer "In4.Cu")
		(net "M_B_CPU0_SA_DQS_DP<8>")
	)
	(arc
		(start 340.141814 -262.383016)
		(mid 339.95786 -262.433145)
		(end 339.773006 -262.386318)
		(width 0.088646)
		(layer "In4.Cu")
		(net "M_B_CPU0_SA_DQS_DP<8>")
	)
	(arc
		(start 333.188564 -262.383016)
		(mid 332.905862 -262.30724)
		(end 332.62316 -262.383016)
		(width 0.088646)
		(layer "In4.Cu")
		(net "M_B_CPU0_SA_DQS_DP<8>")
	)
	(arc
		(start 336.948018 -262.383016)
		(mid 336.671205 -262.307146)
		(end 336.392774 -262.37692)
		(width 0.088646)
		(layer "In4.Cu")
		(net "M_B_CPU0_SA_DQS_DP<8>")
	)
	(arc
		(start 337.887564 -262.383016)
		(mid 337.605006 -262.307367)
		(end 337.322414 -262.383016)
		(width 0.088646)
		(layer "In4.Cu")
		(net "M_B_CPU0_SA_DQS_DP<8>")
	)
	(segment
		(start 339.014562 -264.778236)
		(end 339.014562 -265.313922)
		(width 0.20066)
		(layer "F.Cu")
		(net "M_B_CPU0_SA_DQS_DP<7>")
	)
	(segment
		(start 291.09162 -292.777926)
		(end 290.830508 -292.516814)
		(width 0.20066)
		(layer "F.Cu")
		(net "M_B_CPU0_SA_DQS_DP<7>")
	)
	(segment
		(start 292.67531 -292.08603)
		(end 292.477952 -292.08603)
		(width 0.20066)
		(layer "F.Cu")
		(net "M_B_CPU0_SA_DQS_DP<7>")
	)
	(segment
		(start 292.921944 -292.091872)
		(end 292.681152 -292.091872)
		(width 0.101854)
		(layer "F.Cu")
		(net "M_B_CPU0_SA_DQS_DP<7>")
	)
	(segment
		(start 291.425884 -292.777926)
		(end 291.09162 -292.777926)
		(width 0.20066)
		(layer "F.Cu")
		(net "M_B_CPU0_SA_DQS_DP<7>")
	)
	(segment
		(start 297.148504 -292.777926)
		(end 296.543984 -292.777926)
		(width 0.20066)
		(layer "F.Cu")
		(net "M_B_CPU0_SA_DQS_DP<7>")
	)
	(segment
		(start 299.029882 -292.516814)
		(end 297.899582 -292.516814)
		(width 0.20066)
		(layer "F.Cu")
		(net "M_B_CPU0_SA_DQS_DP<7>")
	)
	(segment
		(start 297.409616 -292.516814)
		(end 297.148504 -292.777926)
		(width 0.20066)
		(layer "F.Cu")
		(net "M_B_CPU0_SA_DQS_DP<7>")
	)
	(segment
		(start 291.848286 -292.355524)
		(end 291.425884 -292.777926)
		(width 0.20066)
		(layer "F.Cu")
		(net "M_B_CPU0_SA_DQS_DP<7>")
	)
	(segment
		(start 295.000426 -292.091872)
		(end 292.921944 -292.091872)
		(width 0.1016)
		(layer "F.Cu")
		(net "M_B_CPU0_SA_DQS_DP<7>")
	)
	(segment
		(start 297.899582 -292.516814)
		(end 297.409616 -292.516814)
		(width 0.20066)
		(layer "F.Cu")
		(net "M_B_CPU0_SA_DQS_DP<7>")
	)
	(segment
		(start 292.208458 -292.355524)
		(end 291.848286 -292.355524)
		(width 0.20066)
		(layer "F.Cu")
		(net "M_B_CPU0_SA_DQS_DP<7>")
	)
	(segment
		(start 292.681152 -292.091872)
		(end 292.67531 -292.08603)
		(width 0.101854)
		(layer "F.Cu")
		(net "M_B_CPU0_SA_DQS_DP<7>")
	)
	(segment
		(start 295.907968 -292.352984)
		(end 295.403016 -292.352984)
		(width 0.20066)
		(layer "F.Cu")
		(net "M_B_CPU0_SA_DQS_DP<7>")
	)
	(segment
		(start 290.830508 -292.516814)
		(end 290.355782 -292.516814)
		(width 0.20066)
		(layer "F.Cu")
		(net "M_B_CPU0_SA_DQS_DP<7>")
	)
	(segment
		(start 292.477952 -292.08603)
		(end 292.208458 -292.355524)
		(width 0.20066)
		(layer "F.Cu")
		(net "M_B_CPU0_SA_DQS_DP<7>")
	)
	(segment
		(start 296.543984 -292.777926)
		(end 295.907968 -292.352984)
		(width 0.20066)
		(layer "F.Cu")
		(net "M_B_CPU0_SA_DQS_DP<7>")
	)
	(segment
		(start 295.403016 -292.352984)
		(end 295.141904 -292.091872)
		(width 0.20066)
		(layer "F.Cu")
		(net "M_B_CPU0_SA_DQS_DP<7>")
	)
	(segment
		(start 339.014562 -265.313922)
		(end 339.014816 -265.314176)
		(width 0.20066)
		(layer "F.Cu")
		(net "M_B_CPU0_SA_DQS_DP<7>")
	)
	(segment
		(start 295.141904 -292.091872)
		(end 295.000426 -292.091872)
		(width 0.20066)
		(layer "F.Cu")
		(net "M_B_CPU0_SA_DQS_DP<7>")
	)
	(segment
		(start 300.126654 -292.99789)
		(end 299.837348 -292.99789)
		(width 0.18288)
		(layer "In2.Cu")
		(net "M_B_CPU0_SA_DQS_DP<7>")
	)
	(segment
		(start 306.798726 -287.09239)
		(end 306.798726 -287.208468)
		(width 0.18288)
		(layer "In2.Cu")
		(net "M_B_CPU0_SA_DQS_DP<7>")
	)
	(segment
		(start 331.560932 -264.875518)
		(end 330.0095 -266.42695)
		(width 0.088646)
		(layer "In2.Cu")
		(net "M_B_CPU0_SA_DQS_DP<7>")
	)
	(segment
		(start 304.299366 -288.693098)
		(end 304.271172 -288.721292)
		(width 0.16002)
		(layer "In2.Cu")
		(net "M_B_CPU0_SA_DQS_DP<7>")
	)
	(segment
		(start 305.936904 -288.07029)
		(end 304.922174 -288.07029)
		(width 0.18288)
		(layer "In2.Cu")
		(net "M_B_CPU0_SA_DQS_DP<7>")
	)
	(segment
		(start 300.2534 -292.871144)
		(end 300.225206 -292.899338)
		(width 0.16002)
		(layer "In2.Cu")
		(net "M_B_CPU0_SA_DQS_DP<7>")
	)
	(segment
		(start 330.0095 -266.42695)
		(end 329.925172 -266.42695)
		(width 0.088646)
		(layer "In2.Cu")
		(net "M_B_CPU0_SA_DQS_DP<7>")
	)
	(segment
		(start 307.717444 -286.173672)
		(end 306.798726 -287.09239)
		(width 0.18288)
		(layer "In2.Cu")
		(net "M_B_CPU0_SA_DQS_DP<7>")
	)
	(segment
		(start 317.528194 -278.223472)
		(end 317.528194 -279.337262)
		(width 0.18288)
		(layer "In2.Cu")
		(net "M_B_CPU0_SA_DQS_DP<7>")
	)
	(segment
		(start 302.24222 -291.914834)
		(end 302.214026 -291.943028)
		(width 0.16002)
		(layer "In2.Cu")
		(net "M_B_CPU0_SA_DQS_DP<7>")
	)
	(segment
		(start 302.014382 -292.158928)
		(end 301.998126 -292.158928)
		(width 0.16002)
		(layer "In2.Cu")
		(net "M_B_CPU0_SA_DQS_DP<7>")
	)
	(segment
		(start 309.334408 -285.548578)
		(end 308.342538 -285.548578)
		(width 0.18288)
		(layer "In2.Cu")
		(net "M_B_CPU0_SA_DQS_DP<7>")
	)
	(segment
		(start 309.567834 -285.315152)
		(end 309.334408 -285.548578)
		(width 0.18288)
		(layer "In2.Cu")
		(net "M_B_CPU0_SA_DQS_DP<7>")
	)
	(segment
		(start 300.4693 -292.655244)
		(end 300.4693 -292.670992)
		(width 0.16002)
		(layer "In2.Cu")
		(net "M_B_CPU0_SA_DQS_DP<7>")
	)
	(segment
		(start 331.966062 -264.875518)
		(end 331.560932 -264.875518)
		(width 0.088646)
		(layer "In2.Cu")
		(net "M_B_CPU0_SA_DQS_DP<7>")
	)
	(segment
		(start 309.811928 -285.087314)
		(end 309.612284 -285.286958)
		(width 0.16002)
		(layer "In2.Cu")
		(net "M_B_CPU0_SA_DQS_DP<7>")
	)
	(segment
		(start 302.950118 -291.206936)
		(end 302.24222 -291.914834)
		(width 0.18288)
		(layer "In2.Cu")
		(net "M_B_CPU0_SA_DQS_DP<7>")
	)
	(segment
		(start 303.774094 -289.218116)
		(end 302.950118 -291.206936)
		(width 0.18288)
		(layer "In2.Cu")
		(net "M_B_CPU0_SA_DQS_DP<7>")
	)
	(segment
		(start 314.131198 -282.742894)
		(end 314.11545 -282.742894)
		(width 0.16002)
		(layer "In2.Cu")
		(net "M_B_CPU0_SA_DQS_DP<7>")
	)
	(segment
		(start 307.961538 -285.929578)
		(end 307.961538 -285.945326)
		(width 0.16002)
		(layer "In2.Cu")
		(net "M_B_CPU0_SA_DQS_DP<7>")
	)
	(segment
		(start 300.225206 -292.899338)
		(end 300.126654 -292.99789)
		(width 0.18288)
		(layer "In2.Cu")
		(net "M_B_CPU0_SA_DQS_DP<7>")
	)
	(segment
		(start 306.11445 -287.909)
		(end 306.098194 -287.909)
		(width 0.16002)
		(layer "In2.Cu")
		(net "M_B_CPU0_SA_DQS_DP<7>")
	)
	(segment
		(start 301.832264 -292.32479)
		(end 300.799754 -292.32479)
		(width 0.18288)
		(layer "In2.Cu")
		(net "M_B_CPU0_SA_DQS_DP<7>")
	)
	(segment
		(start 309.940706 -284.94228)
		(end 309.840122 -285.042864)
		(width 0.18288)
		(layer "In2.Cu")
		(net "M_B_CPU0_SA_DQS_DP<7>")
	)
	(segment
		(start 314.214002 -282.825698)
		(end 314.159392 -282.771088)
		(width 0.18288)
		(layer "In2.Cu")
		(net "M_B_CPU0_SA_DQS_DP<7>")
	)
	(segment
		(start 307.761386 -286.145478)
		(end 307.745638 -286.145478)
		(width 0.16002)
		(layer "In2.Cu")
		(net "M_B_CPU0_SA_DQS_DP<7>")
	)
	(segment
		(start 309.840122 -285.042864)
		(end 309.811928 -285.071058)
		(width 0.16002)
		(layer "In2.Cu")
		(net "M_B_CPU0_SA_DQS_DP<7>")
	)
	(segment
		(start 302.214026 -291.943028)
		(end 302.214026 -291.959284)
		(width 0.16002)
		(layer "In2.Cu")
		(net "M_B_CPU0_SA_DQS_DP<7>")
	)
	(segment
		(start 311.764934 -282.83027)
		(end 309.940706 -284.654498)
		(width 0.18288)
		(layer "In2.Cu")
		(net "M_B_CPU0_SA_DQS_DP<7>")
	)
	(segment
		(start 301.998126 -292.158928)
		(end 301.969932 -292.187122)
		(width 0.16002)
		(layer "In2.Cu")
		(net "M_B_CPU0_SA_DQS_DP<7>")
	)
	(segment
		(start 312.009028 -282.586176)
		(end 312.009028 -282.601924)
		(width 0.16002)
		(layer "In2.Cu")
		(net "M_B_CPU0_SA_DQS_DP<7>")
	)
	(segment
		(start 338.369656 -264.83183)
		(end 338.357464 -264.824718)
		(width 0.088646)
		(layer "In2.Cu")
		(net "M_B_CPU0_SA_DQS_DP<7>")
	)
	(segment
		(start 302.214026 -291.959284)
		(end 302.014382 -292.158928)
		(width 0.16002)
		(layer "In2.Cu")
		(net "M_B_CPU0_SA_DQS_DP<7>")
	)
	(segment
		(start 304.515266 -288.477198)
		(end 304.515266 -288.492946)
		(width 0.16002)
		(layer "In2.Cu")
		(net "M_B_CPU0_SA_DQS_DP<7>")
	)
	(segment
		(start 312.009028 -282.601924)
		(end 311.808876 -282.802076)
		(width 0.16002)
		(layer "In2.Cu")
		(net "M_B_CPU0_SA_DQS_DP<7>")
	)
	(segment
		(start 338.702142 -265.314176)
		(end 338.636356 -265.24839)
		(width 0.088646)
		(layer "In2.Cu")
		(net "M_B_CPU0_SA_DQS_DP<7>")
	)
	(segment
		(start 312.037222 -282.557982)
		(end 312.009028 -282.586176)
		(width 0.16002)
		(layer "In2.Cu")
		(net "M_B_CPU0_SA_DQS_DP<7>")
	)
	(segment
		(start 307.961538 -285.945326)
		(end 307.761386 -286.145478)
		(width 0.16002)
		(layer "In2.Cu")
		(net "M_B_CPU0_SA_DQS_DP<7>")
	)
	(segment
		(start 313.915298 -282.542742)
		(end 313.915298 -282.526994)
		(width 0.16002)
		(layer "In2.Cu")
		(net "M_B_CPU0_SA_DQS_DP<7>")
	)
	(segment
		(start 313.746134 -282.35783)
		(end 312.237374 -282.35783)
		(width 0.18288)
		(layer "In2.Cu")
		(net "M_B_CPU0_SA_DQS_DP<7>")
	)
	(segment
		(start 306.798726 -287.208468)
		(end 306.342288 -287.664906)
		(width 0.18288)
		(layer "In2.Cu")
		(net "M_B_CPU0_SA_DQS_DP<7>")
	)
	(segment
		(start 311.793128 -282.802076)
		(end 311.764934 -282.83027)
		(width 0.16002)
		(layer "In2.Cu")
		(net "M_B_CPU0_SA_DQS_DP<7>")
	)
	(segment
		(start 311.808876 -282.802076)
		(end 311.793128 -282.802076)
		(width 0.16002)
		(layer "In2.Cu")
		(net "M_B_CPU0_SA_DQS_DP<7>")
	)
	(segment
		(start 301.969932 -292.187122)
		(end 301.832264 -292.32479)
		(width 0.18288)
		(layer "In2.Cu")
		(net "M_B_CPU0_SA_DQS_DP<7>")
	)
	(segment
		(start 312.237374 -282.35783)
		(end 312.037222 -282.557982)
		(width 0.18288)
		(layer "In2.Cu")
		(net "M_B_CPU0_SA_DQS_DP<7>")
	)
	(segment
		(start 299.662596 -292.823138)
		(end 299.336206 -292.823138)
		(width 0.18288)
		(layer "In2.Cu")
		(net "M_B_CPU0_SA_DQS_DP<7>")
	)
	(segment
		(start 339.014816 -265.314176)
		(end 338.702142 -265.314176)
		(width 0.088646)
		(layer "In2.Cu")
		(net "M_B_CPU0_SA_DQS_DP<7>")
	)
	(segment
		(start 304.922174 -288.07029)
		(end 304.54346 -288.449004)
		(width 0.18288)
		(layer "In2.Cu")
		(net "M_B_CPU0_SA_DQS_DP<7>")
	)
	(segment
		(start 307.989732 -285.901384)
		(end 307.961538 -285.929578)
		(width 0.16002)
		(layer "In2.Cu")
		(net "M_B_CPU0_SA_DQS_DP<7>")
	)
	(segment
		(start 308.342538 -285.548578)
		(end 307.989732 -285.901384)
		(width 0.18288)
		(layer "In2.Cu")
		(net "M_B_CPU0_SA_DQS_DP<7>")
	)
	(segment
		(start 300.4693 -292.670992)
		(end 300.269148 -292.871144)
		(width 0.16002)
		(layer "In2.Cu")
		(net "M_B_CPU0_SA_DQS_DP<7>")
	)
	(segment
		(start 314.971938 -282.344876)
		(end 314.491116 -282.825698)
		(width 0.18288)
		(layer "In2.Cu")
		(net "M_B_CPU0_SA_DQS_DP<7>")
	)
	(segment
		(start 306.314094 -287.6931)
		(end 306.314094 -287.709356)
		(width 0.16002)
		(layer "In2.Cu")
		(net "M_B_CPU0_SA_DQS_DP<7>")
	)
	(segment
		(start 309.940706 -284.654498)
		(end 309.940706 -284.94228)
		(width 0.18288)
		(layer "In2.Cu")
		(net "M_B_CPU0_SA_DQS_DP<7>")
	)
	(segment
		(start 314.491116 -282.825698)
		(end 314.214002 -282.825698)
		(width 0.18288)
		(layer "In2.Cu")
		(net "M_B_CPU0_SA_DQS_DP<7>")
	)
	(segment
		(start 313.915298 -282.526994)
		(end 313.887104 -282.4988)
		(width 0.16002)
		(layer "In2.Cu")
		(net "M_B_CPU0_SA_DQS_DP<7>")
	)
	(segment
		(start 317.528194 -279.337262)
		(end 314.971938 -281.893518)
		(width 0.18288)
		(layer "In2.Cu")
		(net "M_B_CPU0_SA_DQS_DP<7>")
	)
	(segment
		(start 306.07 -287.937194)
		(end 305.936904 -288.07029)
		(width 0.18288)
		(layer "In2.Cu")
		(net "M_B_CPU0_SA_DQS_DP<7>")
	)
	(segment
		(start 304.315114 -288.693098)
		(end 304.299366 -288.693098)
		(width 0.16002)
		(layer "In2.Cu")
		(net "M_B_CPU0_SA_DQS_DP<7>")
	)
	(segment
		(start 328.11974 -268.232382)
		(end 327.092056 -268.65961)
		(width 0.18288)
		(layer "In2.Cu")
		(net "M_B_CPU0_SA_DQS_DP<7>")
	)
	(segment
		(start 304.515266 -288.492946)
		(end 304.315114 -288.693098)
		(width 0.16002)
		(layer "In2.Cu")
		(net "M_B_CPU0_SA_DQS_DP<7>")
	)
	(segment
		(start 306.314094 -287.709356)
		(end 306.11445 -287.909)
		(width 0.16002)
		(layer "In2.Cu")
		(net "M_B_CPU0_SA_DQS_DP<7>")
	)
	(segment
		(start 300.269148 -292.871144)
		(end 300.2534 -292.871144)
		(width 0.16002)
		(layer "In2.Cu")
		(net "M_B_CPU0_SA_DQS_DP<7>")
	)
	(segment
		(start 314.11545 -282.742894)
		(end 313.915298 -282.542742)
		(width 0.16002)
		(layer "In2.Cu")
		(net "M_B_CPU0_SA_DQS_DP<7>")
	)
	(segment
		(start 309.612284 -285.286958)
		(end 309.596028 -285.286958)
		(width 0.16002)
		(layer "In2.Cu")
		(net "M_B_CPU0_SA_DQS_DP<7>")
	)
	(segment
		(start 304.54346 -288.449004)
		(end 304.515266 -288.477198)
		(width 0.16002)
		(layer "In2.Cu")
		(net "M_B_CPU0_SA_DQS_DP<7>")
	)
	(segment
		(start 300.799754 -292.32479)
		(end 300.497494 -292.62705)
		(width 0.18288)
		(layer "In2.Cu")
		(net "M_B_CPU0_SA_DQS_DP<7>")
	)
	(segment
		(start 306.098194 -287.909)
		(end 306.07 -287.937194)
		(width 0.16002)
		(layer "In2.Cu")
		(net "M_B_CPU0_SA_DQS_DP<7>")
	)
	(segment
		(start 309.811928 -285.071058)
		(end 309.811928 -285.087314)
		(width 0.16002)
		(layer "In2.Cu")
		(net "M_B_CPU0_SA_DQS_DP<7>")
	)
	(segment
		(start 329.925172 -266.42695)
		(end 328.11974 -268.232382)
		(width 0.18288)
		(layer "In2.Cu")
		(net "M_B_CPU0_SA_DQS_DP<7>")
	)
	(segment
		(start 299.336206 -292.823138)
		(end 299.029882 -292.516814)
		(width 0.18288)
		(layer "In2.Cu")
		(net "M_B_CPU0_SA_DQS_DP<7>")
	)
	(segment
		(start 327.092056 -268.65961)
		(end 317.528194 -278.223472)
		(width 0.18288)
		(layer "In2.Cu")
		(net "M_B_CPU0_SA_DQS_DP<7>")
	)
	(segment
		(start 300.497494 -292.62705)
		(end 300.4693 -292.655244)
		(width 0.16002)
		(layer "In2.Cu")
		(net "M_B_CPU0_SA_DQS_DP<7>")
	)
	(segment
		(start 314.971938 -281.893518)
		(end 314.971938 -282.344876)
		(width 0.18288)
		(layer "In2.Cu")
		(net "M_B_CPU0_SA_DQS_DP<7>")
	)
	(segment
		(start 314.159392 -282.771088)
		(end 314.131198 -282.742894)
		(width 0.16002)
		(layer "In2.Cu")
		(net "M_B_CPU0_SA_DQS_DP<7>")
	)
	(segment
		(start 309.596028 -285.286958)
		(end 309.567834 -285.315152)
		(width 0.16002)
		(layer "In2.Cu")
		(net "M_B_CPU0_SA_DQS_DP<7>")
	)
	(segment
		(start 304.271172 -288.721292)
		(end 303.774094 -289.218116)
		(width 0.18288)
		(layer "In2.Cu")
		(net "M_B_CPU0_SA_DQS_DP<7>")
	)
	(segment
		(start 306.342288 -287.664906)
		(end 306.314094 -287.6931)
		(width 0.16002)
		(layer "In2.Cu")
		(net "M_B_CPU0_SA_DQS_DP<7>")
	)
	(segment
		(start 313.887104 -282.4988)
		(end 313.746134 -282.35783)
		(width 0.18288)
		(layer "In2.Cu")
		(net "M_B_CPU0_SA_DQS_DP<7>")
	)
	(segment
		(start 307.745638 -286.145478)
		(end 307.717444 -286.173672)
		(width 0.16002)
		(layer "In2.Cu")
		(net "M_B_CPU0_SA_DQS_DP<7>")
	)
	(segment
		(start 299.837348 -292.99789)
		(end 299.662596 -292.823138)
		(width 0.18288)
		(layer "In2.Cu")
		(net "M_B_CPU0_SA_DQS_DP<7>")
	)
	(arc
		(start 335.538064 -264.824718)
		(mid 335.255362 -264.748942)
		(end 334.97266 -264.824718)
		(width 0.088646)
		(layer "In2.Cu")
		(net "M_B_CPU0_SA_DQS_DP<7>")
	)
	(arc
		(start 338.357464 -264.824718)
		(mid 338.074762 -264.748942)
		(end 337.79206 -264.824718)
		(width 0.088646)
		(layer "In2.Cu")
		(net "M_B_CPU0_SA_DQS_DP<7>")
	)
	(arc
		(start 333.09306 -264.824718)
		(mid 332.905862 -264.874861)
		(end 332.718664 -264.824718)
		(width 0.088646)
		(layer "In2.Cu")
		(net "M_B_CPU0_SA_DQS_DP<7>")
	)
	(arc
		(start 336.85226 -264.824718)
		(mid 336.665062 -264.874861)
		(end 336.477864 -264.824718)
		(width 0.088646)
		(layer "In2.Cu")
		(net "M_B_CPU0_SA_DQS_DP<7>")
	)
	(arc
		(start 332.15326 -264.824718)
		(mid 332.078367 -264.857862)
		(end 331.998066 -264.873994)
		(width 0.088646)
		(layer "In2.Cu")
		(net "M_B_CPU0_SA_DQS_DP<7>")
	)
	(arc
		(start 337.417664 -264.824718)
		(mid 337.134962 -264.748942)
		(end 336.85226 -264.824718)
		(width 0.088646)
		(layer "In2.Cu")
		(net "M_B_CPU0_SA_DQS_DP<7>")
	)
	(arc
		(start 334.03286 -264.824718)
		(mid 333.845662 -264.874861)
		(end 333.658464 -264.824718)
		(width 0.088646)
		(layer "In2.Cu")
		(net "M_B_CPU0_SA_DQS_DP<7>")
	)
	(arc
		(start 334.97266 -264.824718)
		(mid 334.785462 -264.874861)
		(end 334.598264 -264.824718)
		(width 0.088646)
		(layer "In2.Cu")
		(net "M_B_CPU0_SA_DQS_DP<7>")
	)
	(arc
		(start 338.633562 -265.227562)
		(mid 338.545291 -265.000549)
		(end 338.369656 -264.83183)
		(width 0.088646)
		(layer "In2.Cu")
		(net "M_B_CPU0_SA_DQS_DP<7>")
	)
	(arc
		(start 336.477864 -264.824718)
		(mid 336.195162 -264.748942)
		(end 335.91246 -264.824718)
		(width 0.088646)
		(layer "In2.Cu")
		(net "M_B_CPU0_SA_DQS_DP<7>")
	)
	(arc
		(start 335.91246 -264.824718)
		(mid 335.725262 -264.874861)
		(end 335.538064 -264.824718)
		(width 0.088646)
		(layer "In2.Cu")
		(net "M_B_CPU0_SA_DQS_DP<7>")
	)
	(arc
		(start 334.598264 -264.824718)
		(mid 334.315562 -264.748942)
		(end 334.03286 -264.824718)
		(width 0.088646)
		(layer "In2.Cu")
		(net "M_B_CPU0_SA_DQS_DP<7>")
	)
	(arc
		(start 337.79206 -264.824718)
		(mid 337.604862 -264.874861)
		(end 337.417664 -264.824718)
		(width 0.088646)
		(layer "In2.Cu")
		(net "M_B_CPU0_SA_DQS_DP<7>")
	)
	(arc
		(start 332.718664 -264.824718)
		(mid 332.435962 -264.748942)
		(end 332.15326 -264.824718)
		(width 0.088646)
		(layer "In2.Cu")
		(net "M_B_CPU0_SA_DQS_DP<7>")
	)
	(arc
		(start 333.658464 -264.824718)
		(mid 333.375762 -264.748942)
		(end 333.09306 -264.824718)
		(width 0.088646)
		(layer "In2.Cu")
		(net "M_B_CPU0_SA_DQS_DP<7>")
	)
	(arc
		(start 338.636356 -265.24839)
		(mid 338.635055 -265.237963)
		(end 338.633562 -265.227562)
		(width 0.088646)
		(layer "In2.Cu")
		(net "M_B_CPU0_SA_DQS_DP<7>")
	)
	(arc
		(start 331.998066 -264.873994)
		(mid 331.98208 -264.875096)
		(end 331.966062 -264.875518)
		(width 0.088646)
		(layer "In2.Cu")
		(net "M_B_CPU0_SA_DQS_DP<7>")
	)
	(segment
		(start 292.67531 -301.436024)
		(end 292.477952 -301.436024)
		(width 0.20066)
		(layer "F.Cu")
		(net "M_B_CPU0_SA_DQS_DP<6>")
	)
	(segment
		(start 292.477952 -301.436024)
		(end 292.208458 -301.705518)
		(width 0.20066)
		(layer "F.Cu")
		(net "M_B_CPU0_SA_DQS_DP<6>")
	)
	(segment
		(start 295.907968 -301.702978)
		(end 295.403016 -301.702978)
		(width 0.20066)
		(layer "F.Cu")
		(net "M_B_CPU0_SA_DQS_DP<6>")
	)
	(segment
		(start 297.148504 -302.12792)
		(end 296.543984 -302.12792)
		(width 0.20066)
		(layer "F.Cu")
		(net "M_B_CPU0_SA_DQS_DP<6>")
	)
	(segment
		(start 291.09162 -302.12792)
		(end 290.830508 -301.866808)
		(width 0.20066)
		(layer "F.Cu")
		(net "M_B_CPU0_SA_DQS_DP<6>")
	)
	(segment
		(start 297.899582 -301.866808)
		(end 297.409616 -301.866808)
		(width 0.20066)
		(layer "F.Cu")
		(net "M_B_CPU0_SA_DQS_DP<6>")
	)
	(segment
		(start 296.543984 -302.12792)
		(end 295.907968 -301.702978)
		(width 0.20066)
		(layer "F.Cu")
		(net "M_B_CPU0_SA_DQS_DP<6>")
	)
	(segment
		(start 299.029882 -301.866808)
		(end 297.899582 -301.866808)
		(width 0.20066)
		(layer "F.Cu")
		(net "M_B_CPU0_SA_DQS_DP<6>")
	)
	(segment
		(start 341.364316 -272.103342)
		(end 341.364316 -272.639028)
		(width 0.20066)
		(layer "F.Cu")
		(net "M_B_CPU0_SA_DQS_DP<6>")
	)
	(segment
		(start 291.848286 -301.705518)
		(end 291.425884 -302.12792)
		(width 0.20066)
		(layer "F.Cu")
		(net "M_B_CPU0_SA_DQS_DP<6>")
	)
	(segment
		(start 295.141904 -301.441866)
		(end 295.000426 -301.441866)
		(width 0.20066)
		(layer "F.Cu")
		(net "M_B_CPU0_SA_DQS_DP<6>")
	)
	(segment
		(start 295.403016 -301.702978)
		(end 295.141904 -301.441866)
		(width 0.20066)
		(layer "F.Cu")
		(net "M_B_CPU0_SA_DQS_DP<6>")
	)
	(segment
		(start 297.409616 -301.866808)
		(end 297.148504 -302.12792)
		(width 0.20066)
		(layer "F.Cu")
		(net "M_B_CPU0_SA_DQS_DP<6>")
	)
	(segment
		(start 341.364316 -272.639028)
		(end 341.364062 -272.639282)
		(width 0.20066)
		(layer "F.Cu")
		(net "M_B_CPU0_SA_DQS_DP<6>")
	)
	(segment
		(start 292.681152 -301.441866)
		(end 292.67531 -301.436024)
		(width 0.101854)
		(layer "F.Cu")
		(net "M_B_CPU0_SA_DQS_DP<6>")
	)
	(segment
		(start 292.921944 -301.441866)
		(end 292.681152 -301.441866)
		(width 0.101854)
		(layer "F.Cu")
		(net "M_B_CPU0_SA_DQS_DP<6>")
	)
	(segment
		(start 290.830508 -301.866808)
		(end 290.355782 -301.866808)
		(width 0.20066)
		(layer "F.Cu")
		(net "M_B_CPU0_SA_DQS_DP<6>")
	)
	(segment
		(start 295.000426 -301.441866)
		(end 292.921944 -301.441866)
		(width 0.1016)
		(layer "F.Cu")
		(net "M_B_CPU0_SA_DQS_DP<6>")
	)
	(segment
		(start 292.208458 -301.705518)
		(end 291.848286 -301.705518)
		(width 0.20066)
		(layer "F.Cu")
		(net "M_B_CPU0_SA_DQS_DP<6>")
	)
	(segment
		(start 291.425884 -302.12792)
		(end 291.09162 -302.12792)
		(width 0.20066)
		(layer "F.Cu")
		(net "M_B_CPU0_SA_DQS_DP<6>")
	)
	(segment
		(start 322.435982 -287.56864)
		(end 322.273168 -287.63595)
		(width 0.18288)
		(layer "In4.Cu")
		(net "M_B_CPU0_SA_DQS_DP<6>")
	)
	(segment
		(start 309.530496 -298.306744)
		(end 308.794404 -298.306744)
		(width 0.18288)
		(layer "In4.Cu")
		(net "M_B_CPU0_SA_DQS_DP<6>")
	)
	(segment
		(start 321.615054 -289.549586)
		(end 320.456814 -292.346634)
		(width 0.18288)
		(layer "In4.Cu")
		(net "M_B_CPU0_SA_DQS_DP<6>")
	)
	(segment
		(start 323.466714 -285.080964)
		(end 323.3039 -285.148274)
		(width 0.18288)
		(layer "In4.Cu")
		(net "M_B_CPU0_SA_DQS_DP<6>")
	)
	(segment
		(start 340.784688 -272.194274)
		(end 340.707218 -272.14957)
		(width 0.088646)
		(layer "In4.Cu")
		(net "M_B_CPU0_SA_DQS_DP<6>")
	)
	(segment
		(start 327.917048 -279.419558)
		(end 327.917302 -279.59558)
		(width 0.18288)
		(layer "In4.Cu")
		(net "M_B_CPU0_SA_DQS_DP<6>")
	)
	(segment
		(start 337.332828 -272.143474)
		(end 337.322414 -272.14957)
		(width 0.088646)
		(layer "In4.Cu")
		(net "M_B_CPU0_SA_DQS_DP<6>")
	)
	(segment
		(start 322.06311 -288.143188)
		(end 322.13042 -288.305748)
		(width 0.18288)
		(layer "In4.Cu")
		(net "M_B_CPU0_SA_DQS_DP<6>")
	)
	(segment
		(start 331.764894 -276.069806)
		(end 331.741526 -276.069806)
		(width 0.088646)
		(layer "In4.Cu")
		(net "M_B_CPU0_SA_DQS_DP<6>")
	)
	(segment
		(start 334.04175 -272.95856)
		(end 334.03286 -272.96364)
		(width 0.088646)
		(layer "In4.Cu")
		(net "M_B_CPU0_SA_DQS_DP<6>")
	)
	(segment
		(start 322.951348 -286.324802)
		(end 322.788534 -286.392112)
		(width 0.18288)
		(layer "In4.Cu")
		(net "M_B_CPU0_SA_DQS_DP<6>")
	)
	(segment
		(start 329.431396 -278.077422)
		(end 329.255374 -278.077676)
		(width 0.18288)
		(layer "In4.Cu")
		(net "M_B_CPU0_SA_DQS_DP<6>")
	)
	(segment
		(start 325.064882 -282.455366)
		(end 324.191884 -283.330396)
		(width 0.18288)
		(layer "In4.Cu")
		(net "M_B_CPU0_SA_DQS_DP<6>")
	)
	(segment
		(start 327.917302 -279.59558)
		(end 327.529952 -279.983946)
		(width 0.18288)
		(layer "In4.Cu")
		(net "M_B_CPU0_SA_DQS_DP<6>")
	)
	(segment
		(start 321.547744 -289.387026)
		(end 321.615054 -289.549586)
		(width 0.18288)
		(layer "In4.Cu")
		(net "M_B_CPU0_SA_DQS_DP<6>")
	)
	(segment
		(start 333.094584 -274.59051)
		(end 333.09306 -274.591272)
		(width 0.088646)
		(layer "In4.Cu")
		(net "M_B_CPU0_SA_DQS_DP<6>")
	)
	(segment
		(start 330.206096 -277.124414)
		(end 329.818492 -277.513034)
		(width 0.18288)
		(layer "In4.Cu")
		(net "M_B_CPU0_SA_DQS_DP<6>")
	)
	(segment
		(start 333.092298 -274.59178)
		(end 333.091282 -274.592288)
		(width 0.088646)
		(layer "In4.Cu")
		(net "M_B_CPU0_SA_DQS_DP<6>")
	)
	(segment
		(start 325.452232 -281.890724)
		(end 325.064628 -282.279344)
		(width 0.18288)
		(layer "In4.Cu")
		(net "M_B_CPU0_SA_DQS_DP<6>")
	)
	(segment
		(start 321.757802 -288.879788)
		(end 321.547744 -289.387026)
		(width 0.18288)
		(layer "In4.Cu")
		(net "M_B_CPU0_SA_DQS_DP<6>")
	)
	(segment
		(start 333.09306 -274.591272)
		(end 333.092298 -274.59178)
		(width 0.088646)
		(layer "In4.Cu")
		(net "M_B_CPU0_SA_DQS_DP<6>")
	)
	(segment
		(start 323.609208 -284.411674)
		(end 323.676518 -284.574234)
		(width 0.18288)
		(layer "In4.Cu")
		(net "M_B_CPU0_SA_DQS_DP<6>")
	)
	(segment
		(start 327.529952 -279.983946)
		(end 327.35393 -279.9842)
		(width 0.18288)
		(layer "In4.Cu")
		(net "M_B_CPU0_SA_DQS_DP<6>")
	)
	(segment
		(start 332.810358 -275.08073)
		(end 332.810358 -275.09216)
		(width 0.088646)
		(layer "In4.Cu")
		(net "M_B_CPU0_SA_DQS_DP<6>")
	)
	(segment
		(start 325.064628 -282.279344)
		(end 325.064882 -282.455366)
		(width 0.18288)
		(layer "In4.Cu")
		(net "M_B_CPU0_SA_DQS_DP<6>")
	)
	(segment
		(start 320.456814 -292.346634)
		(end 315.940948 -296.8625)
		(width 0.18288)
		(layer "In4.Cu")
		(net "M_B_CPU0_SA_DQS_DP<6>")
	)
	(segment
		(start 328.480674 -279.030684)
		(end 328.304652 -279.030938)
		(width 0.18288)
		(layer "In4.Cu")
		(net "M_B_CPU0_SA_DQS_DP<6>")
	)
	(segment
		(start 333.564738 -273.776694)
		(end 333.563214 -273.777456)
		(width 0.088646)
		(layer "In4.Cu")
		(net "M_B_CPU0_SA_DQS_DP<6>")
	)
	(segment
		(start 322.578476 -286.89935)
		(end 322.645786 -287.06191)
		(width 0.18288)
		(layer "In4.Cu")
		(net "M_B_CPU0_SA_DQS_DP<6>")
	)
	(segment
		(start 330.382118 -277.12416)
		(end 330.206096 -277.124414)
		(width 0.18288)
		(layer "In4.Cu")
		(net "M_B_CPU0_SA_DQS_DP<6>")
	)
	(segment
		(start 333.091282 -274.592288)
		(end 333.089504 -274.593304)
		(width 0.088646)
		(layer "In4.Cu")
		(net "M_B_CPU0_SA_DQS_DP<6>")
	)
	(segment
		(start 331.824584 -276.129496)
		(end 331.764894 -276.069806)
		(width 0.088646)
		(layer "In4.Cu")
		(net "M_B_CPU0_SA_DQS_DP<6>")
	)
	(segment
		(start 310.18607 -298.042076)
		(end 309.795164 -298.042076)
		(width 0.18288)
		(layer "In4.Cu")
		(net "M_B_CPU0_SA_DQS_DP<6>")
	)
	(segment
		(start 322.13042 -288.305748)
		(end 321.920616 -288.812478)
		(width 0.18288)
		(layer "In4.Cu")
		(net "M_B_CPU0_SA_DQS_DP<6>")
	)
	(segment
		(start 325.628254 -281.89047)
		(end 325.452232 -281.890724)
		(width 0.18288)
		(layer "In4.Cu")
		(net "M_B_CPU0_SA_DQS_DP<6>")
	)
	(segment
		(start 307.781452 -298.97578)
		(end 306.563268 -300.194218)
		(width 0.18288)
		(layer "In4.Cu")
		(net "M_B_CPU0_SA_DQS_DP<6>")
	)
	(segment
		(start 315.940948 -296.8625)
		(end 313.483498 -296.8625)
		(width 0.18288)
		(layer "In4.Cu")
		(net "M_B_CPU0_SA_DQS_DP<6>")
	)
	(segment
		(start 310.456326 -298.312332)
		(end 310.18607 -298.042076)
		(width 0.18288)
		(layer "In4.Cu")
		(net "M_B_CPU0_SA_DQS_DP<6>")
	)
	(segment
		(start 299.780706 -302.132238)
		(end 299.295312 -302.132238)
		(width 0.18288)
		(layer "In4.Cu")
		(net "M_B_CPU0_SA_DQS_DP<6>")
	)
	(segment
		(start 329.818492 -277.513034)
		(end 329.818746 -277.689056)
		(width 0.18288)
		(layer "In4.Cu")
		(net "M_B_CPU0_SA_DQS_DP<6>")
	)
	(segment
		(start 333.562452 -273.777964)
		(end 333.557118 -273.781012)
		(width 0.088646)
		(layer "In4.Cu")
		(net "M_B_CPU0_SA_DQS_DP<6>")
	)
	(segment
		(start 326.015604 -281.502104)
		(end 325.628254 -281.89047)
		(width 0.18288)
		(layer "In4.Cu")
		(net "M_B_CPU0_SA_DQS_DP<6>")
	)
	(segment
		(start 326.015604 -281.326082)
		(end 326.015604 -281.502104)
		(width 0.18288)
		(layer "In4.Cu")
		(net "M_B_CPU0_SA_DQS_DP<6>")
	)
	(segment
		(start 329.255374 -278.077676)
		(end 328.86777 -278.466296)
		(width 0.18288)
		(layer "In4.Cu")
		(net "M_B_CPU0_SA_DQS_DP<6>")
	)
	(segment
		(start 306.016914 -300.194218)
		(end 304.360834 -301.850298)
		(width 0.18288)
		(layer "In4.Cu")
		(net "M_B_CPU0_SA_DQS_DP<6>")
	)
	(segment
		(start 323.676518 -284.574234)
		(end 323.466714 -285.080964)
		(width 0.18288)
		(layer "In4.Cu")
		(net "M_B_CPU0_SA_DQS_DP<6>")
	)
	(segment
		(start 322.645786 -287.06191)
		(end 322.435982 -287.56864)
		(width 0.18288)
		(layer "In4.Cu")
		(net "M_B_CPU0_SA_DQS_DP<6>")
	)
	(segment
		(start 323.161152 -285.818072)
		(end 322.951348 -286.324802)
		(width 0.18288)
		(layer "In4.Cu")
		(net "M_B_CPU0_SA_DQS_DP<6>")
	)
	(segment
		(start 326.96658 -280.548842)
		(end 326.57923 -280.937208)
		(width 0.18288)
		(layer "In4.Cu")
		(net "M_B_CPU0_SA_DQS_DP<6>")
	)
	(segment
		(start 338.827364 -272.14957)
		(end 338.812632 -272.140934)
		(width 0.088646)
		(layer "In4.Cu")
		(net "M_B_CPU0_SA_DQS_DP<6>")
	)
	(segment
		(start 321.920616 -288.812478)
		(end 321.757802 -288.879788)
		(width 0.18288)
		(layer "In4.Cu")
		(net "M_B_CPU0_SA_DQS_DP<6>")
	)
	(segment
		(start 333.572104 -273.772376)
		(end 333.564738 -273.776694)
		(width 0.088646)
		(layer "In4.Cu")
		(net "M_B_CPU0_SA_DQS_DP<6>")
	)
	(segment
		(start 331.741526 -276.069806)
		(end 331.435964 -276.069806)
		(width 0.18288)
		(layer "In4.Cu")
		(net "M_B_CPU0_SA_DQS_DP<6>")
	)
	(segment
		(start 323.98208 -283.837126)
		(end 323.819266 -283.904436)
		(width 0.18288)
		(layer "In4.Cu")
		(net "M_B_CPU0_SA_DQS_DP<6>")
	)
	(segment
		(start 322.273168 -287.63595)
		(end 322.06311 -288.143188)
		(width 0.18288)
		(layer "In4.Cu")
		(net "M_B_CPU0_SA_DQS_DP<6>")
	)
	(segment
		(start 329.818746 -277.689056)
		(end 329.431396 -278.077422)
		(width 0.18288)
		(layer "In4.Cu")
		(net "M_B_CPU0_SA_DQS_DP<6>")
	)
	(segment
		(start 331.435964 -276.069806)
		(end 330.382118 -277.12416)
		(width 0.18288)
		(layer "In4.Cu")
		(net "M_B_CPU0_SA_DQS_DP<6>")
	)
	(segment
		(start 304.360834 -301.850298)
		(end 303.801272 -301.850298)
		(width 0.18288)
		(layer "In4.Cu")
		(net "M_B_CPU0_SA_DQS_DP<6>")
	)
	(segment
		(start 333.10195 -274.586192)
		(end 333.094584 -274.59051)
		(width 0.088646)
		(layer "In4.Cu")
		(net "M_B_CPU0_SA_DQS_DP<6>")
	)
	(segment
		(start 324.191884 -283.330396)
		(end 323.98208 -283.837126)
		(width 0.18288)
		(layer "In4.Cu")
		(net "M_B_CPU0_SA_DQS_DP<6>")
	)
	(segment
		(start 340.156546 -272.140934)
		(end 340.141814 -272.14957)
		(width 0.088646)
		(layer "In4.Cu")
		(net "M_B_CPU0_SA_DQS_DP<6>")
	)
	(segment
		(start 334.220312 -272.625058)
		(end 334.220312 -272.639282)
		(width 0.088646)
		(layer "In4.Cu")
		(net "M_B_CPU0_SA_DQS_DP<6>")
	)
	(segment
		(start 309.795164 -298.042076)
		(end 309.530496 -298.306744)
		(width 0.18288)
		(layer "In4.Cu")
		(net "M_B_CPU0_SA_DQS_DP<6>")
	)
	(segment
		(start 335.068164 -272.14957)
		(end 335.053432 -272.140934)
		(width 0.088646)
		(layer "In4.Cu")
		(net "M_B_CPU0_SA_DQS_DP<6>")
	)
	(segment
		(start 328.304652 -279.030938)
		(end 327.917048 -279.419558)
		(width 0.18288)
		(layer "In4.Cu")
		(net "M_B_CPU0_SA_DQS_DP<6>")
	)
	(segment
		(start 326.966326 -280.37282)
		(end 326.96658 -280.548842)
		(width 0.18288)
		(layer "In4.Cu")
		(net "M_B_CPU0_SA_DQS_DP<6>")
	)
	(segment
		(start 332.788768 -275.306282)
		(end 331.965554 -276.129496)
		(width 0.088646)
		(layer "In4.Cu")
		(net "M_B_CPU0_SA_DQS_DP<6>")
	)
	(segment
		(start 326.403208 -280.937462)
		(end 326.015604 -281.326082)
		(width 0.18288)
		(layer "In4.Cu")
		(net "M_B_CPU0_SA_DQS_DP<6>")
	)
	(segment
		(start 323.819266 -283.904436)
		(end 323.609208 -284.411674)
		(width 0.18288)
		(layer "In4.Cu")
		(net "M_B_CPU0_SA_DQS_DP<6>")
	)
	(segment
		(start 308.368192 -298.732702)
		(end 307.781452 -298.97578)
		(width 0.18288)
		(layer "In4.Cu")
		(net "M_B_CPU0_SA_DQS_DP<6>")
	)
	(segment
		(start 333.750412 -273.453098)
		(end 333.750666 -273.453098)
		(width 0.088646)
		(layer "In4.Cu")
		(net "M_B_CPU0_SA_DQS_DP<6>")
	)
	(segment
		(start 328.86777 -278.466296)
		(end 328.868024 -278.642318)
		(width 0.18288)
		(layer "In4.Cu")
		(net "M_B_CPU0_SA_DQS_DP<6>")
	)
	(segment
		(start 328.868024 -278.642318)
		(end 328.480674 -279.030684)
		(width 0.18288)
		(layer "In4.Cu")
		(net "M_B_CPU0_SA_DQS_DP<6>")
	)
	(segment
		(start 336.948018 -272.14957)
		(end 336.937604 -272.143474)
		(width 0.088646)
		(layer "In4.Cu")
		(net "M_B_CPU0_SA_DQS_DP<6>")
	)
	(segment
		(start 332.810358 -275.09216)
		(end 332.788768 -275.306282)
		(width 0.088646)
		(layer "In4.Cu")
		(net "M_B_CPU0_SA_DQS_DP<6>")
	)
	(segment
		(start 299.295312 -302.132238)
		(end 299.029882 -301.866808)
		(width 0.18288)
		(layer "In4.Cu")
		(net "M_B_CPU0_SA_DQS_DP<6>")
	)
	(segment
		(start 299.990764 -302.342296)
		(end 299.780706 -302.132238)
		(width 0.18288)
		(layer "In4.Cu")
		(net "M_B_CPU0_SA_DQS_DP<6>")
	)
	(segment
		(start 308.794404 -298.306744)
		(end 308.368192 -298.732702)
		(width 0.18288)
		(layer "In4.Cu")
		(net "M_B_CPU0_SA_DQS_DP<6>")
	)
	(segment
		(start 331.965554 -276.129496)
		(end 331.824584 -276.129496)
		(width 0.088646)
		(layer "In4.Cu")
		(net "M_B_CPU0_SA_DQS_DP<6>")
	)
	(segment
		(start 313.483498 -296.8625)
		(end 312.033666 -298.312332)
		(width 0.18288)
		(layer "In4.Cu")
		(net "M_B_CPU0_SA_DQS_DP<6>")
	)
	(segment
		(start 326.57923 -280.937208)
		(end 326.403208 -280.937462)
		(width 0.18288)
		(layer "In4.Cu")
		(net "M_B_CPU0_SA_DQS_DP<6>")
	)
	(segment
		(start 334.03286 -272.96364)
		(end 334.026764 -272.967196)
		(width 0.088646)
		(layer "In4.Cu")
		(net "M_B_CPU0_SA_DQS_DP<6>")
	)
	(segment
		(start 333.563214 -273.777456)
		(end 333.562452 -273.777964)
		(width 0.088646)
		(layer "In4.Cu")
		(net "M_B_CPU0_SA_DQS_DP<6>")
	)
	(segment
		(start 339.212174 -272.143474)
		(end 339.20176 -272.14957)
		(width 0.088646)
		(layer "In4.Cu")
		(net "M_B_CPU0_SA_DQS_DP<6>")
	)
	(segment
		(start 306.563268 -300.194218)
		(end 306.016914 -300.194218)
		(width 0.18288)
		(layer "In4.Cu")
		(net "M_B_CPU0_SA_DQS_DP<6>")
	)
	(segment
		(start 302.614076 -302.342296)
		(end 299.990764 -302.342296)
		(width 0.18288)
		(layer "In4.Cu")
		(net "M_B_CPU0_SA_DQS_DP<6>")
	)
	(segment
		(start 323.093842 -285.655512)
		(end 323.161152 -285.818072)
		(width 0.18288)
		(layer "In4.Cu")
		(net "M_B_CPU0_SA_DQS_DP<6>")
	)
	(segment
		(start 303.801272 -301.850298)
		(end 302.614076 -302.342296)
		(width 0.18288)
		(layer "In4.Cu")
		(net "M_B_CPU0_SA_DQS_DP<6>")
	)
	(segment
		(start 327.35393 -279.9842)
		(end 326.966326 -280.37282)
		(width 0.18288)
		(layer "In4.Cu")
		(net "M_B_CPU0_SA_DQS_DP<6>")
	)
	(segment
		(start 322.788534 -286.392112)
		(end 322.578476 -286.89935)
		(width 0.18288)
		(layer "In4.Cu")
		(net "M_B_CPU0_SA_DQS_DP<6>")
	)
	(segment
		(start 312.033666 -298.312332)
		(end 310.456326 -298.312332)
		(width 0.18288)
		(layer "In4.Cu")
		(net "M_B_CPU0_SA_DQS_DP<6>")
	)
	(segment
		(start 333.089504 -274.593304)
		(end 333.086964 -274.594828)
		(width 0.088646)
		(layer "In4.Cu")
		(net "M_B_CPU0_SA_DQS_DP<6>")
	)
	(segment
		(start 323.3039 -285.148274)
		(end 323.093842 -285.655512)
		(width 0.18288)
		(layer "In4.Cu")
		(net "M_B_CPU0_SA_DQS_DP<6>")
	)
	(arc
		(start 333.086964 -274.594828)
		(mid 332.884377 -274.801179)
		(end 332.810358 -275.08073)
		(width 0.088646)
		(layer "In4.Cu")
		(net "M_B_CPU0_SA_DQS_DP<6>")
	)
	(arc
		(start 335.053432 -272.140934)
		(mid 334.776991 -272.073768)
		(end 334.50276 -272.14957)
		(width 0.088646)
		(layer "In4.Cu")
		(net "M_B_CPU0_SA_DQS_DP<6>")
	)
	(arc
		(start 338.812632 -272.140934)
		(mid 338.536191 -272.073768)
		(end 338.26196 -272.14957)
		(width 0.088646)
		(layer "In4.Cu")
		(net "M_B_CPU0_SA_DQS_DP<6>")
	)
	(arc
		(start 336.38236 -272.14957)
		(mid 336.195162 -272.199713)
		(end 336.007964 -272.14957)
		(width 0.088646)
		(layer "In4.Cu")
		(net "M_B_CPU0_SA_DQS_DP<6>")
	)
	(arc
		(start 333.557118 -273.781012)
		(mid 333.354531 -273.987363)
		(end 333.280512 -274.266914)
		(width 0.088646)
		(layer "In4.Cu")
		(net "M_B_CPU0_SA_DQS_DP<6>")
	)
	(arc
		(start 335.44256 -272.14957)
		(mid 335.255362 -272.199713)
		(end 335.068164 -272.14957)
		(width 0.088646)
		(layer "In4.Cu")
		(net "M_B_CPU0_SA_DQS_DP<6>")
	)
	(arc
		(start 336.937604 -272.143474)
		(mid 336.659172 -272.07366)
		(end 336.38236 -272.14957)
		(width 0.088646)
		(layer "In4.Cu")
		(net "M_B_CPU0_SA_DQS_DP<6>")
	)
	(arc
		(start 340.141814 -272.14957)
		(mid 339.954616 -272.199713)
		(end 339.767418 -272.14957)
		(width 0.088646)
		(layer "In4.Cu")
		(net "M_B_CPU0_SA_DQS_DP<6>")
	)
	(arc
		(start 338.26196 -272.14957)
		(mid 338.074762 -272.199713)
		(end 337.887564 -272.14957)
		(width 0.088646)
		(layer "In4.Cu")
		(net "M_B_CPU0_SA_DQS_DP<6>")
	)
	(arc
		(start 341.364062 -272.639282)
		(mid 341.088921 -272.39784)
		(end 340.784688 -272.194274)
		(width 0.088646)
		(layer "In4.Cu")
		(net "M_B_CPU0_SA_DQS_DP<6>")
	)
	(arc
		(start 336.007964 -272.14957)
		(mid 335.725262 -272.073828)
		(end 335.44256 -272.14957)
		(width 0.088646)
		(layer "In4.Cu")
		(net "M_B_CPU0_SA_DQS_DP<6>")
	)
	(arc
		(start 334.50276 -272.14957)
		(mid 334.299455 -272.350436)
		(end 334.220312 -272.625058)
		(width 0.088646)
		(layer "In4.Cu")
		(net "M_B_CPU0_SA_DQS_DP<6>")
	)
	(arc
		(start 339.767418 -272.14957)
		(mid 339.490605 -272.073734)
		(end 339.212174 -272.143474)
		(width 0.088646)
		(layer "In4.Cu")
		(net "M_B_CPU0_SA_DQS_DP<6>")
	)
	(arc
		(start 333.750666 -273.453098)
		(mid 333.702987 -273.635998)
		(end 333.572104 -273.772376)
		(width 0.088646)
		(layer "In4.Cu")
		(net "M_B_CPU0_SA_DQS_DP<6>")
	)
	(arc
		(start 334.026764 -272.967196)
		(mid 333.824351 -273.173609)
		(end 333.750412 -273.453098)
		(width 0.088646)
		(layer "In4.Cu")
		(net "M_B_CPU0_SA_DQS_DP<6>")
	)
	(arc
		(start 340.707218 -272.14957)
		(mid 340.432989 -272.073645)
		(end 340.156546 -272.140934)
		(width 0.088646)
		(layer "In4.Cu")
		(net "M_B_CPU0_SA_DQS_DP<6>")
	)
	(arc
		(start 333.280512 -274.266914)
		(mid 333.232833 -274.449814)
		(end 333.10195 -274.586192)
		(width 0.088646)
		(layer "In4.Cu")
		(net "M_B_CPU0_SA_DQS_DP<6>")
	)
	(arc
		(start 337.322414 -272.14957)
		(mid 337.135216 -272.199713)
		(end 336.948018 -272.14957)
		(width 0.088646)
		(layer "In4.Cu")
		(net "M_B_CPU0_SA_DQS_DP<6>")
	)
	(arc
		(start 334.220312 -272.639282)
		(mid 334.172633 -272.822182)
		(end 334.04175 -272.95856)
		(width 0.088646)
		(layer "In4.Cu")
		(net "M_B_CPU0_SA_DQS_DP<6>")
	)
	(arc
		(start 339.20176 -272.14957)
		(mid 339.014562 -272.199713)
		(end 338.827364 -272.14957)
		(width 0.088646)
		(layer "In4.Cu")
		(net "M_B_CPU0_SA_DQS_DP<6>")
	)
	(arc
		(start 337.887564 -272.14957)
		(mid 337.611005 -272.073861)
		(end 337.332828 -272.143474)
		(width 0.088646)
		(layer "In4.Cu")
		(net "M_B_CPU0_SA_DQS_DP<6>")
	)
	(segment
		(start 339.010752 -274.54479)
		(end 339.014562 -274.54479)
		(width 0.20066)
		(layer "F.Cu")
		(net "M_B_CPU0_SA_DQS_DP<5>")
	)
	(segment
		(start 297.899582 -311.216802)
		(end 297.409616 -311.216802)
		(width 0.20066)
		(layer "F.Cu")
		(net "M_B_CPU0_SA_DQS_DP<5>")
	)
	(segment
		(start 295.403016 -311.052972)
		(end 295.141904 -310.79186)
		(width 0.20066)
		(layer "F.Cu")
		(net "M_B_CPU0_SA_DQS_DP<5>")
	)
	(segment
		(start 292.208458 -311.055512)
		(end 291.848286 -311.055512)
		(width 0.20066)
		(layer "F.Cu")
		(net "M_B_CPU0_SA_DQS_DP<5>")
	)
	(segment
		(start 296.543984 -311.477914)
		(end 295.907968 -311.052972)
		(width 0.20066)
		(layer "F.Cu")
		(net "M_B_CPU0_SA_DQS_DP<5>")
	)
	(segment
		(start 295.000426 -310.79186)
		(end 292.921944 -310.79186)
		(width 0.1016)
		(layer "F.Cu")
		(net "M_B_CPU0_SA_DQS_DP<5>")
	)
	(segment
		(start 292.477952 -310.786018)
		(end 292.208458 -311.055512)
		(width 0.20066)
		(layer "F.Cu")
		(net "M_B_CPU0_SA_DQS_DP<5>")
	)
	(segment
		(start 339.014816 -275.08073)
		(end 339.011006 -275.08073)
		(width 0.20066)
		(layer "F.Cu")
		(net "M_B_CPU0_SA_DQS_DP<5>")
	)
	(segment
		(start 291.425884 -311.477914)
		(end 291.09162 -311.477914)
		(width 0.20066)
		(layer "F.Cu")
		(net "M_B_CPU0_SA_DQS_DP<5>")
	)
	(segment
		(start 295.141904 -310.79186)
		(end 295.000426 -310.79186)
		(width 0.20066)
		(layer "F.Cu")
		(net "M_B_CPU0_SA_DQS_DP<5>")
	)
	(segment
		(start 295.907968 -311.052972)
		(end 295.403016 -311.052972)
		(width 0.20066)
		(layer "F.Cu")
		(net "M_B_CPU0_SA_DQS_DP<5>")
	)
	(segment
		(start 297.409616 -311.216802)
		(end 297.148504 -311.477914)
		(width 0.20066)
		(layer "F.Cu")
		(net "M_B_CPU0_SA_DQS_DP<5>")
	)
	(segment
		(start 290.830508 -311.216802)
		(end 290.355782 -311.216802)
		(width 0.20066)
		(layer "F.Cu")
		(net "M_B_CPU0_SA_DQS_DP<5>")
	)
	(segment
		(start 291.848286 -311.055512)
		(end 291.425884 -311.477914)
		(width 0.20066)
		(layer "F.Cu")
		(net "M_B_CPU0_SA_DQS_DP<5>")
	)
	(segment
		(start 297.148504 -311.477914)
		(end 296.543984 -311.477914)
		(width 0.20066)
		(layer "F.Cu")
		(net "M_B_CPU0_SA_DQS_DP<5>")
	)
	(segment
		(start 292.681152 -310.79186)
		(end 292.67531 -310.786018)
		(width 0.101854)
		(layer "F.Cu")
		(net "M_B_CPU0_SA_DQS_DP<5>")
	)
	(segment
		(start 292.67531 -310.786018)
		(end 292.477952 -310.786018)
		(width 0.20066)
		(layer "F.Cu")
		(net "M_B_CPU0_SA_DQS_DP<5>")
	)
	(segment
		(start 292.921944 -310.79186)
		(end 292.681152 -310.79186)
		(width 0.101854)
		(layer "F.Cu")
		(net "M_B_CPU0_SA_DQS_DP<5>")
	)
	(segment
		(start 299.029882 -311.216802)
		(end 297.899582 -311.216802)
		(width 0.20066)
		(layer "F.Cu")
		(net "M_B_CPU0_SA_DQS_DP<5>")
	)
	(segment
		(start 291.09162 -311.477914)
		(end 290.830508 -311.216802)
		(width 0.20066)
		(layer "F.Cu")
		(net "M_B_CPU0_SA_DQS_DP<5>")
	)
	(arc
		(start 339.011006 -275.08073)
		(mid 339.010816 -274.81276)
		(end 339.010752 -274.54479)
		(width 0.20066)
		(layer "F.Cu")
		(net "M_B_CPU0_SA_DQS_DP<5>")
	)
	(segment
		(start 312.23204 -310.409082)
		(end 312.034682 -310.60644)
		(width 0.18288)
		(layer "In2.Cu")
		(net "M_B_CPU0_SA_DQS_DP<5>")
	)
	(segment
		(start 307.90642 -311.484518)
		(end 307.90642 -311.500266)
		(width 0.16002)
		(layer "In2.Cu")
		(net "M_B_CPU0_SA_DQS_DP<5>")
	)
	(segment
		(start 313.967876 -310.634634)
		(end 313.939682 -310.60644)
		(width 0.16002)
		(layer "In2.Cu")
		(net "M_B_CPU0_SA_DQS_DP<5>")
	)
	(segment
		(start 330.489306 -283.350462)
		(end 330.38034 -283.613352)
		(width 0.18288)
		(layer "In2.Cu")
		(net "M_B_CPU0_SA_DQS_DP<5>")
	)
	(segment
		(start 311.806336 -310.850534)
		(end 311.790588 -310.850534)
		(width 0.16002)
		(layer "In2.Cu")
		(net "M_B_CPU0_SA_DQS_DP<5>")
	)
	(segment
		(start 332.673706 -279.307798)
		(end 332.589378 -279.307798)
		(width 0.088646)
		(layer "In2.Cu")
		(net "M_B_CPU0_SA_DQS_DP<5>")
	)
	(segment
		(start 334.689958 -275.072856)
		(end 334.689958 -275.08073)
		(width 0.088646)
		(layer "In2.Cu")
		(net "M_B_CPU0_SA_DQS_DP<5>")
	)
	(segment
		(start 330.489306 -281.40787)
		(end 330.489306 -283.350462)
		(width 0.18288)
		(layer "In2.Cu")
		(net "M_B_CPU0_SA_DQS_DP<5>")
	)
	(segment
		(start 309.867808 -311.484518)
		(end 309.839614 -311.456324)
		(width 0.16002)
		(layer "In2.Cu")
		(net "M_B_CPU0_SA_DQS_DP<5>")
	)
	(segment
		(start 311.790588 -310.850534)
		(end 311.762394 -310.878728)
		(width 0.16002)
		(layer "In2.Cu")
		(net "M_B_CPU0_SA_DQS_DP<5>")
	)
	(segment
		(start 313.939682 -310.60644)
		(end 313.742324 -310.409082)
		(width 0.18288)
		(layer "In2.Cu")
		(net "M_B_CPU0_SA_DQS_DP<5>")
	)
	(segment
		(start 310.23052 -311.84723)
		(end 310.111902 -311.728612)
		(width 0.18288)
		(layer "In2.Cu")
		(net "M_B_CPU0_SA_DQS_DP<5>")
	)
	(segment
		(start 300.428914 -311.418478)
		(end 300.40072 -311.446672)
		(width 0.16002)
		(layer "In2.Cu")
		(net "M_B_CPU0_SA_DQS_DP<5>")
	)
	(segment
		(start 314.563252 -310.98744)
		(end 314.320682 -310.98744)
		(width 0.18288)
		(layer "In2.Cu")
		(net "M_B_CPU0_SA_DQS_DP<5>")
	)
	(segment
		(start 334.511396 -275.400008)
		(end 334.503268 -275.40458)
		(width 0.088646)
		(layer "In2.Cu")
		(net "M_B_CPU0_SA_DQS_DP<5>")
	)
	(segment
		(start 334.503268 -275.40458)
		(end 334.502506 -275.405088)
		(width 0.088646)
		(layer "In2.Cu")
		(net "M_B_CPU0_SA_DQS_DP<5>")
	)
	(segment
		(start 304.665634 -312.429652)
		(end 304.46599 -312.230008)
		(width 0.16002)
		(layer "In2.Cu")
		(net "M_B_CPU0_SA_DQS_DP<5>")
	)
	(segment
		(start 312.006488 -310.634634)
		(end 312.006488 -310.650382)
		(width 0.16002)
		(layer "In2.Cu")
		(net "M_B_CPU0_SA_DQS_DP<5>")
	)
	(segment
		(start 302.324008 -311.484772)
		(end 302.295814 -311.456578)
		(width 0.16002)
		(layer "In2.Cu")
		(net "M_B_CPU0_SA_DQS_DP<5>")
	)
	(segment
		(start 300.18482 -311.662572)
		(end 300.156626 -311.690766)
		(width 0.16002)
		(layer "In2.Cu")
		(net "M_B_CPU0_SA_DQS_DP<5>")
	)
	(segment
		(start 334.51165 -278.65578)
		(end 334.50276 -278.66086)
		(width 0.088646)
		(layer "In2.Cu")
		(net "M_B_CPU0_SA_DQS_DP<5>")
	)
	(segment
		(start 313.742324 -310.409082)
		(end 312.23204 -310.409082)
		(width 0.18288)
		(layer "In2.Cu")
		(net "M_B_CPU0_SA_DQS_DP<5>")
	)
	(segment
		(start 333.315818 -279.090628)
		(end 332.890876 -279.090628)
		(width 0.088646)
		(layer "In2.Cu")
		(net "M_B_CPU0_SA_DQS_DP<5>")
	)
	(segment
		(start 304.437796 -312.185558)
		(end 304.157888 -311.90565)
		(width 0.18288)
		(layer "In2.Cu")
		(net "M_B_CPU0_SA_DQS_DP<5>")
	)
	(segment
		(start 300.40072 -311.446672)
		(end 300.40072 -311.46242)
		(width 0.16002)
		(layer "In2.Cu")
		(net "M_B_CPU0_SA_DQS_DP<5>")
	)
	(segment
		(start 304.710084 -312.457846)
		(end 304.68189 -312.429652)
		(width 0.16002)
		(layer "In2.Cu")
		(net "M_B_CPU0_SA_DQS_DP<5>")
	)
	(segment
		(start 310.083708 -311.700418)
		(end 310.06796 -311.700418)
		(width 0.16002)
		(layer "In2.Cu")
		(net "M_B_CPU0_SA_DQS_DP<5>")
	)
	(segment
		(start 339.014816 -275.08073)
		(end 338.702142 -275.08073)
		(width 0.088646)
		(layer "In2.Cu")
		(net "M_B_CPU0_SA_DQS_DP<5>")
	)
	(segment
		(start 310.111902 -311.728612)
		(end 310.083708 -311.700418)
		(width 0.16002)
		(layer "In2.Cu")
		(net "M_B_CPU0_SA_DQS_DP<5>")
	)
	(segment
		(start 307.934614 -311.456324)
		(end 307.90642 -311.484518)
		(width 0.16002)
		(layer "In2.Cu")
		(net "M_B_CPU0_SA_DQS_DP<5>")
	)
	(segment
		(start 334.51165 -277.027894)
		(end 334.50276 -277.032974)
		(width 0.088646)
		(layer "In2.Cu")
		(net "M_B_CPU0_SA_DQS_DP<5>")
	)
	(segment
		(start 314.168028 -310.850534)
		(end 313.967876 -310.650382)
		(width 0.16002)
		(layer "In2.Cu")
		(net "M_B_CPU0_SA_DQS_DP<5>")
	)
	(segment
		(start 314.808362 -310.88584)
		(end 314.563252 -310.98744)
		(width 0.18288)
		(layer "In2.Cu")
		(net "M_B_CPU0_SA_DQS_DP<5>")
	)
	(segment
		(start 300.120812 -311.72658)
		(end 299.838364 -311.72658)
		(width 0.18288)
		(layer "In2.Cu")
		(net "M_B_CPU0_SA_DQS_DP<5>")
	)
	(segment
		(start 309.642256 -311.258966)
		(end 308.131972 -311.258966)
		(width 0.18288)
		(layer "In2.Cu")
		(net "M_B_CPU0_SA_DQS_DP<5>")
	)
	(segment
		(start 322.369688 -299.013626)
		(end 321.805046 -301.852584)
		(width 0.18288)
		(layer "In2.Cu")
		(net "M_B_CPU0_SA_DQS_DP<5>")
	)
	(segment
		(start 300.200568 -311.662572)
		(end 300.18482 -311.662572)
		(width 0.16002)
		(layer "In2.Cu")
		(net "M_B_CPU0_SA_DQS_DP<5>")
	)
	(segment
		(start 306.17668 -312.457846)
		(end 306.07 -312.564526)
		(width 0.18288)
		(layer "In2.Cu")
		(net "M_B_CPU0_SA_DQS_DP<5>")
	)
	(segment
		(start 304.816764 -312.564526)
		(end 304.710084 -312.457846)
		(width 0.18288)
		(layer "In2.Cu")
		(net "M_B_CPU0_SA_DQS_DP<5>")
	)
	(segment
		(start 302.52416 -311.700672)
		(end 302.324008 -311.50052)
		(width 0.16002)
		(layer "In2.Cu")
		(net "M_B_CPU0_SA_DQS_DP<5>")
	)
	(segment
		(start 304.68189 -312.429652)
		(end 304.665634 -312.429652)
		(width 0.16002)
		(layer "In2.Cu")
		(net "M_B_CPU0_SA_DQS_DP<5>")
	)
	(segment
		(start 300.156626 -311.690766)
		(end 300.120812 -311.72658)
		(width 0.18288)
		(layer "In2.Cu")
		(net "M_B_CPU0_SA_DQS_DP<5>")
	)
	(segment
		(start 306.204874 -312.429652)
		(end 306.17668 -312.457846)
		(width 0.16002)
		(layer "In2.Cu")
		(net "M_B_CPU0_SA_DQS_DP<5>")
	)
	(segment
		(start 309.867808 -311.500266)
		(end 309.867808 -311.484518)
		(width 0.16002)
		(layer "In2.Cu")
		(net "M_B_CPU0_SA_DQS_DP<5>")
	)
	(segment
		(start 338.702142 -275.08073)
		(end 338.636356 -275.014944)
		(width 0.088646)
		(layer "In2.Cu")
		(net "M_B_CPU0_SA_DQS_DP<5>")
	)
	(segment
		(start 307.90642 -311.500266)
		(end 307.706268 -311.700418)
		(width 0.16002)
		(layer "In2.Cu")
		(net "M_B_CPU0_SA_DQS_DP<5>")
	)
	(segment
		(start 312.006488 -310.650382)
		(end 311.806336 -310.850534)
		(width 0.16002)
		(layer "In2.Cu")
		(net "M_B_CPU0_SA_DQS_DP<5>")
	)
	(segment
		(start 321.805046 -301.852584)
		(end 320.364358 -305.330098)
		(width 0.18288)
		(layer "In2.Cu")
		(net "M_B_CPU0_SA_DQS_DP<5>")
	)
	(segment
		(start 299.838364 -311.72658)
		(end 299.592238 -311.480454)
		(width 0.18288)
		(layer "In2.Cu")
		(net "M_B_CPU0_SA_DQS_DP<5>")
	)
	(segment
		(start 314.183776 -310.850534)
		(end 314.168028 -310.850534)
		(width 0.16002)
		(layer "In2.Cu")
		(net "M_B_CPU0_SA_DQS_DP<5>")
	)
	(segment
		(start 334.220058 -277.508462)
		(end 334.220058 -277.522686)
		(width 0.088646)
		(layer "In2.Cu")
		(net "M_B_CPU0_SA_DQS_DP<5>")
	)
	(segment
		(start 308.131972 -311.258966)
		(end 307.934614 -311.456324)
		(width 0.18288)
		(layer "In2.Cu")
		(net "M_B_CPU0_SA_DQS_DP<5>")
	)
	(segment
		(start 332.589378 -279.307798)
		(end 330.489306 -281.40787)
		(width 0.18288)
		(layer "In2.Cu")
		(net "M_B_CPU0_SA_DQS_DP<5>")
	)
	(segment
		(start 334.315562 -278.711406)
		(end 333.69504 -278.711406)
		(width 0.088646)
		(layer "In2.Cu")
		(net "M_B_CPU0_SA_DQS_DP<5>")
	)
	(segment
		(start 329.650344 -285.375604)
		(end 326.865234 -288.160968)
		(width 0.18288)
		(layer "In2.Cu")
		(net "M_B_CPU0_SA_DQS_DP<5>")
	)
	(segment
		(start 302.539908 -311.700672)
		(end 302.52416 -311.700672)
		(width 0.16002)
		(layer "In2.Cu")
		(net "M_B_CPU0_SA_DQS_DP<5>")
	)
	(segment
		(start 302.295814 -311.456578)
		(end 301.97171 -311.132474)
		(width 0.18288)
		(layer "In2.Cu")
		(net "M_B_CPU0_SA_DQS_DP<5>")
	)
	(segment
		(start 334.51165 -276.389592)
		(end 334.51165 -276.389338)
		(width 0.088646)
		(layer "In2.Cu")
		(net "M_B_CPU0_SA_DQS_DP<5>")
	)
	(segment
		(start 334.503522 -276.384766)
		(end 334.51165 -276.389592)
		(width 0.088646)
		(layer "In2.Cu")
		(net "M_B_CPU0_SA_DQS_DP<5>")
	)
	(segment
		(start 307.69052 -311.700418)
		(end 307.662326 -311.728612)
		(width 0.16002)
		(layer "In2.Cu")
		(net "M_B_CPU0_SA_DQS_DP<5>")
	)
	(segment
		(start 334.496664 -276.380702)
		(end 334.499966 -276.382734)
		(width 0.088646)
		(layer "In2.Cu")
		(net "M_B_CPU0_SA_DQS_DP<5>")
	)
	(segment
		(start 310.06796 -311.700418)
		(end 309.867808 -311.500266)
		(width 0.16002)
		(layer "In2.Cu")
		(net "M_B_CPU0_SA_DQS_DP<5>")
	)
	(segment
		(start 306.420774 -312.213752)
		(end 306.420774 -312.230008)
		(width 0.16002)
		(layer "In2.Cu")
		(net "M_B_CPU0_SA_DQS_DP<5>")
	)
	(segment
		(start 334.496664 -278.008588)
		(end 334.51165 -278.017224)
		(width 0.088646)
		(layer "In2.Cu")
		(net "M_B_CPU0_SA_DQS_DP<5>")
	)
	(segment
		(start 302.568102 -311.728866)
		(end 302.539908 -311.700672)
		(width 0.16002)
		(layer "In2.Cu")
		(net "M_B_CPU0_SA_DQS_DP<5>")
	)
	(segment
		(start 307.662326 -311.728612)
		(end 307.503068 -311.88787)
		(width 0.18288)
		(layer "In2.Cu")
		(net "M_B_CPU0_SA_DQS_DP<5>")
	)
	(segment
		(start 306.448968 -312.185558)
		(end 306.420774 -312.213752)
		(width 0.16002)
		(layer "In2.Cu")
		(net "M_B_CPU0_SA_DQS_DP<5>")
	)
	(segment
		(start 302.744886 -311.90565)
		(end 302.568102 -311.728866)
		(width 0.18288)
		(layer "In2.Cu")
		(net "M_B_CPU0_SA_DQS_DP<5>")
	)
	(segment
		(start 309.839614 -311.456324)
		(end 309.642256 -311.258966)
		(width 0.18288)
		(layer "In2.Cu")
		(net "M_B_CPU0_SA_DQS_DP<5>")
	)
	(segment
		(start 314.320682 -310.98744)
		(end 314.21197 -310.878728)
		(width 0.18288)
		(layer "In2.Cu")
		(net "M_B_CPU0_SA_DQS_DP<5>")
	)
	(segment
		(start 302.324008 -311.50052)
		(end 302.324008 -311.484772)
		(width 0.16002)
		(layer "In2.Cu")
		(net "M_B_CPU0_SA_DQS_DP<5>")
	)
	(segment
		(start 334.50276 -276.384258)
		(end 334.503522 -276.384766)
		(width 0.088646)
		(layer "In2.Cu")
		(net "M_B_CPU0_SA_DQS_DP<5>")
	)
	(segment
		(start 314.21197 -310.878728)
		(end 314.183776 -310.850534)
		(width 0.16002)
		(layer "In2.Cu")
		(net "M_B_CPU0_SA_DQS_DP<5>")
	)
	(segment
		(start 304.157888 -311.90565)
		(end 302.744886 -311.90565)
		(width 0.18288)
		(layer "In2.Cu")
		(net "M_B_CPU0_SA_DQS_DP<5>")
	)
	(segment
		(start 300.714918 -311.132474)
		(end 300.428914 -311.418478)
		(width 0.18288)
		(layer "In2.Cu")
		(net "M_B_CPU0_SA_DQS_DP<5>")
	)
	(segment
		(start 330.38034 -283.613352)
		(end 329.650344 -285.375604)
		(width 0.18288)
		(layer "In2.Cu")
		(net "M_B_CPU0_SA_DQS_DP<5>")
	)
	(segment
		(start 333.69504 -278.711406)
		(end 333.315818 -279.090628)
		(width 0.088646)
		(layer "In2.Cu")
		(net "M_B_CPU0_SA_DQS_DP<5>")
	)
	(segment
		(start 334.220058 -275.876258)
		(end 334.220058 -275.8948)
		(width 0.088646)
		(layer "In2.Cu")
		(net "M_B_CPU0_SA_DQS_DP<5>")
	)
	(segment
		(start 306.746656 -311.88787)
		(end 306.448968 -312.185558)
		(width 0.18288)
		(layer "In2.Cu")
		(net "M_B_CPU0_SA_DQS_DP<5>")
	)
	(segment
		(start 306.07 -312.564526)
		(end 304.816764 -312.564526)
		(width 0.18288)
		(layer "In2.Cu")
		(net "M_B_CPU0_SA_DQS_DP<5>")
	)
	(segment
		(start 334.987392 -274.582636)
		(end 334.97266 -274.591272)
		(width 0.088646)
		(layer "In2.Cu")
		(net "M_B_CPU0_SA_DQS_DP<5>")
	)
	(segment
		(start 332.890876 -279.090628)
		(end 332.673706 -279.307798)
		(width 0.088646)
		(layer "In2.Cu")
		(net "M_B_CPU0_SA_DQS_DP<5>")
	)
	(segment
		(start 304.46599 -312.213752)
		(end 304.437796 -312.185558)
		(width 0.16002)
		(layer "In2.Cu")
		(net "M_B_CPU0_SA_DQS_DP<5>")
	)
	(segment
		(start 326.865234 -288.160968)
		(end 322.369688 -299.013626)
		(width 0.18288)
		(layer "In2.Cu")
		(net "M_B_CPU0_SA_DQS_DP<5>")
	)
	(segment
		(start 307.503068 -311.88787)
		(end 306.746656 -311.88787)
		(width 0.18288)
		(layer "In2.Cu")
		(net "M_B_CPU0_SA_DQS_DP<5>")
	)
	(segment
		(start 304.46599 -312.230008)
		(end 304.46599 -312.213752)
		(width 0.16002)
		(layer "In2.Cu")
		(net "M_B_CPU0_SA_DQS_DP<5>")
	)
	(segment
		(start 301.97171 -311.132474)
		(end 300.714918 -311.132474)
		(width 0.18288)
		(layer "In2.Cu")
		(net "M_B_CPU0_SA_DQS_DP<5>")
	)
	(segment
		(start 310.793892 -311.84723)
		(end 310.23052 -311.84723)
		(width 0.18288)
		(layer "In2.Cu")
		(net "M_B_CPU0_SA_DQS_DP<5>")
	)
	(segment
		(start 320.364358 -305.330098)
		(end 314.808362 -310.88584)
		(width 0.18288)
		(layer "In2.Cu")
		(net "M_B_CPU0_SA_DQS_DP<5>")
	)
	(segment
		(start 313.967876 -310.650382)
		(end 313.967876 -310.634634)
		(width 0.16002)
		(layer "In2.Cu")
		(net "M_B_CPU0_SA_DQS_DP<5>")
	)
	(segment
		(start 311.762394 -310.878728)
		(end 310.793892 -311.84723)
		(width 0.18288)
		(layer "In2.Cu")
		(net "M_B_CPU0_SA_DQS_DP<5>")
	)
	(segment
		(start 299.293534 -311.480454)
		(end 299.029882 -311.216802)
		(width 0.18288)
		(layer "In2.Cu")
		(net "M_B_CPU0_SA_DQS_DP<5>")
	)
	(segment
		(start 306.420774 -312.230008)
		(end 306.22113 -312.429652)
		(width 0.16002)
		(layer "In2.Cu")
		(net "M_B_CPU0_SA_DQS_DP<5>")
	)
	(segment
		(start 307.706268 -311.700418)
		(end 307.69052 -311.700418)
		(width 0.16002)
		(layer "In2.Cu")
		(net "M_B_CPU0_SA_DQS_DP<5>")
	)
	(segment
		(start 334.499966 -276.382734)
		(end 334.50276 -276.384258)
		(width 0.088646)
		(layer "In2.Cu")
		(net "M_B_CPU0_SA_DQS_DP<5>")
	)
	(segment
		(start 299.592238 -311.480454)
		(end 299.293534 -311.480454)
		(width 0.18288)
		(layer "In2.Cu")
		(net "M_B_CPU0_SA_DQS_DP<5>")
	)
	(segment
		(start 300.40072 -311.46242)
		(end 300.200568 -311.662572)
		(width 0.16002)
		(layer "In2.Cu")
		(net "M_B_CPU0_SA_DQS_DP<5>")
	)
	(segment
		(start 312.034682 -310.60644)
		(end 312.006488 -310.634634)
		(width 0.16002)
		(layer "In2.Cu")
		(net "M_B_CPU0_SA_DQS_DP<5>")
	)
	(segment
		(start 306.22113 -312.429652)
		(end 306.204874 -312.429652)
		(width 0.16002)
		(layer "In2.Cu")
		(net "M_B_CPU0_SA_DQS_DP<5>")
	)
	(arc
		(start 338.636356 -275.014944)
		(mid 338.635055 -275.004517)
		(end 338.633562 -274.994116)
		(width 0.088646)
		(layer "In2.Cu")
		(net "M_B_CPU0_SA_DQS_DP<5>")
	)
	(arc
		(start 334.220058 -275.8948)
		(mid 334.294049 -276.174366)
		(end 334.496664 -276.380702)
		(width 0.088646)
		(layer "In2.Cu")
		(net "M_B_CPU0_SA_DQS_DP<5>")
	)
	(arc
		(start 334.50276 -277.032974)
		(mid 334.299279 -277.233778)
		(end 334.220058 -277.508462)
		(width 0.088646)
		(layer "In2.Cu")
		(net "M_B_CPU0_SA_DQS_DP<5>")
	)
	(arc
		(start 334.220058 -277.522686)
		(mid 334.294049 -277.802252)
		(end 334.496664 -278.008588)
		(width 0.088646)
		(layer "In2.Cu")
		(net "M_B_CPU0_SA_DQS_DP<5>")
	)
	(arc
		(start 336.85226 -274.591272)
		(mid 336.665062 -274.641415)
		(end 336.477864 -274.591272)
		(width 0.088646)
		(layer "In2.Cu")
		(net "M_B_CPU0_SA_DQS_DP<5>")
	)
	(arc
		(start 336.477864 -274.591272)
		(mid 336.195162 -274.515496)
		(end 335.91246 -274.591272)
		(width 0.088646)
		(layer "In2.Cu")
		(net "M_B_CPU0_SA_DQS_DP<5>")
	)
	(arc
		(start 338.633562 -274.994116)
		(mid 338.318964 -274.570916)
		(end 337.79206 -274.591272)
		(width 0.088646)
		(layer "In2.Cu")
		(net "M_B_CPU0_SA_DQS_DP<5>")
	)
	(arc
		(start 334.50276 -278.66086)
		(mid 334.412488 -278.698459)
		(end 334.315562 -278.711406)
		(width 0.088646)
		(layer "In2.Cu")
		(net "M_B_CPU0_SA_DQS_DP<5>")
	)
	(arc
		(start 337.79206 -274.591272)
		(mid 337.604862 -274.641415)
		(end 337.417664 -274.591272)
		(width 0.088646)
		(layer "In2.Cu")
		(net "M_B_CPU0_SA_DQS_DP<5>")
	)
	(arc
		(start 335.91246 -274.591272)
		(mid 335.725262 -274.641415)
		(end 335.538064 -274.591272)
		(width 0.088646)
		(layer "In2.Cu")
		(net "M_B_CPU0_SA_DQS_DP<5>")
	)
	(arc
		(start 334.51165 -276.389338)
		(mid 334.690247 -276.708616)
		(end 334.51165 -277.027894)
		(width 0.088646)
		(layer "In2.Cu")
		(net "M_B_CPU0_SA_DQS_DP<5>")
	)
	(arc
		(start 337.417664 -274.591272)
		(mid 337.134962 -274.515496)
		(end 336.85226 -274.591272)
		(width 0.088646)
		(layer "In2.Cu")
		(net "M_B_CPU0_SA_DQS_DP<5>")
	)
	(arc
		(start 334.689958 -275.08073)
		(mid 334.642279 -275.26363)
		(end 334.511396 -275.400008)
		(width 0.088646)
		(layer "In2.Cu")
		(net "M_B_CPU0_SA_DQS_DP<5>")
	)
	(arc
		(start 334.502506 -275.405088)
		(mid 334.30022 -275.604069)
		(end 334.220058 -275.876258)
		(width 0.088646)
		(layer "In2.Cu")
		(net "M_B_CPU0_SA_DQS_DP<5>")
	)
	(arc
		(start 334.97266 -274.591272)
		(mid 334.767722 -274.794722)
		(end 334.689958 -275.072856)
		(width 0.088646)
		(layer "In2.Cu")
		(net "M_B_CPU0_SA_DQS_DP<5>")
	)
	(arc
		(start 334.51165 -278.017224)
		(mid 334.690247 -278.336502)
		(end 334.51165 -278.65578)
		(width 0.088646)
		(layer "In2.Cu")
		(net "M_B_CPU0_SA_DQS_DP<5>")
	)
	(arc
		(start 335.538064 -274.591272)
		(mid 335.263865 -274.515437)
		(end 334.987392 -274.582636)
		(width 0.088646)
		(layer "In2.Cu")
		(net "M_B_CPU0_SA_DQS_DP<5>")
	)
	(segment
		(start 292.72103 -275.255482)
		(end 292.295834 -275.680678)
		(width 0.20066)
		(layer "F.Cu")
		(net "M_B_CPU0_SA_DQS_DP<4>")
	)
	(segment
		(start 293.799514 -275.516594)
		(end 293.250874 -275.516594)
		(width 0.20066)
		(layer "F.Cu")
		(net "M_B_CPU0_SA_DQS_DP<4>")
	)
	(segment
		(start 286.793686 -275.516594)
		(end 286.255714 -275.516594)
		(width 0.20066)
		(layer "F.Cu")
		(net "M_B_CPU0_SA_DQS_DP<4>")
	)
	(segment
		(start 287.47974 -275.255482)
		(end 287.054798 -275.255482)
		(width 0.20066)
		(layer "F.Cu")
		(net "M_B_CPU0_SA_DQS_DP<4>")
	)
	(segment
		(start 291.556694 -275.94179)
		(end 291.233352 -275.94179)
		(width 0.101854)
		(layer "F.Cu")
		(net "M_B_CPU0_SA_DQS_DP<4>")
	)
	(segment
		(start 293.250874 -275.516594)
		(end 292.989762 -275.255482)
		(width 0.20066)
		(layer "F.Cu")
		(net "M_B_CPU0_SA_DQS_DP<4>")
	)
	(segment
		(start 337.134962 -259.894832)
		(end 337.137502 -259.897372)
		(width 0.20066)
		(layer "F.Cu")
		(net "M_B_CPU0_SA_DQS_DP<4>")
	)
	(segment
		(start 289.013392 -275.951188)
		(end 288.742882 -275.680678)
		(width 0.20066)
		(layer "F.Cu")
		(net "M_B_CPU0_SA_DQS_DP<4>")
	)
	(segment
		(start 291.70884 -275.94179)
		(end 291.556694 -275.94179)
		(width 0.20066)
		(layer "F.Cu")
		(net "M_B_CPU0_SA_DQS_DP<4>")
	)
	(segment
		(start 288.742882 -275.680678)
		(end 288.115756 -275.680678)
		(width 0.20066)
		(layer "F.Cu")
		(net "M_B_CPU0_SA_DQS_DP<4>")
	)
	(segment
		(start 337.137502 -259.897372)
		(end 337.137502 -260.428486)
		(width 0.20066)
		(layer "F.Cu")
		(net "M_B_CPU0_SA_DQS_DP<4>")
	)
	(segment
		(start 291.969952 -275.680678)
		(end 291.70884 -275.94179)
		(width 0.20066)
		(layer "F.Cu")
		(net "M_B_CPU0_SA_DQS_DP<4>")
	)
	(segment
		(start 287.054798 -275.255482)
		(end 286.793686 -275.516594)
		(width 0.20066)
		(layer "F.Cu")
		(net "M_B_CPU0_SA_DQS_DP<4>")
	)
	(segment
		(start 289.240976 -275.94179)
		(end 289.231578 -275.951188)
		(width 0.101854)
		(layer "F.Cu")
		(net "M_B_CPU0_SA_DQS_DP<4>")
	)
	(segment
		(start 294.904414 -275.516594)
		(end 293.799514 -275.516594)
		(width 0.20066)
		(layer "F.Cu")
		(net "M_B_CPU0_SA_DQS_DP<4>")
	)
	(segment
		(start 289.477958 -275.94179)
		(end 289.240976 -275.94179)
		(width 0.101854)
		(layer "F.Cu")
		(net "M_B_CPU0_SA_DQS_DP<4>")
	)
	(segment
		(start 288.115756 -275.680678)
		(end 287.47974 -275.255482)
		(width 0.20066)
		(layer "F.Cu")
		(net "M_B_CPU0_SA_DQS_DP<4>")
	)
	(segment
		(start 291.233352 -275.94179)
		(end 289.477958 -275.94179)
		(width 0.1016)
		(layer "F.Cu")
		(net "M_B_CPU0_SA_DQS_DP<4>")
	)
	(segment
		(start 289.231578 -275.951188)
		(end 289.013392 -275.951188)
		(width 0.20066)
		(layer "F.Cu")
		(net "M_B_CPU0_SA_DQS_DP<4>")
	)
	(segment
		(start 337.137502 -260.428486)
		(end 337.135216 -260.430772)
		(width 0.20066)
		(layer "F.Cu")
		(net "M_B_CPU0_SA_DQS_DP<4>")
	)
	(segment
		(start 292.989762 -275.255482)
		(end 292.72103 -275.255482)
		(width 0.20066)
		(layer "F.Cu")
		(net "M_B_CPU0_SA_DQS_DP<4>")
	)
	(segment
		(start 292.295834 -275.680678)
		(end 291.969952 -275.680678)
		(width 0.20066)
		(layer "F.Cu")
		(net "M_B_CPU0_SA_DQS_DP<4>")
	)
	(segment
		(start 331.966062 -260.869684)
		(end 331.650086 -260.869684)
		(width 0.088646)
		(layer "In2.Cu")
		(net "M_B_CPU0_SA_DQS_DP<4>")
	)
	(segment
		(start 303.957736 -275.02739)
		(end 303.32807 -275.657056)
		(width 0.18288)
		(layer "In2.Cu")
		(net "M_B_CPU0_SA_DQS_DP<4>")
	)
	(segment
		(start 310.076088 -275.880068)
		(end 310.06034 -275.880068)
		(width 0.16002)
		(layer "In2.Cu")
		(net "M_B_CPU0_SA_DQS_DP<4>")
	)
	(segment
		(start 313.424824 -273.13255)
		(end 312.505598 -273.13255)
		(width 0.18288)
		(layer "In2.Cu")
		(net "M_B_CPU0_SA_DQS_DP<4>")
	)
	(segment
		(start 296.631614 -274.96643)
		(end 296.113454 -274.96643)
		(width 0.18288)
		(layer "In2.Cu")
		(net "M_B_CPU0_SA_DQS_DP<4>")
	)
	(segment
		(start 306.996846 -275.671534)
		(end 306.725066 -275.943314)
		(width 0.18288)
		(layer "In2.Cu")
		(net "M_B_CPU0_SA_DQS_DP<4>")
	)
	(segment
		(start 302.560482 -275.851874)
		(end 302.532288 -275.880068)
		(width 0.16002)
		(layer "In2.Cu")
		(net "M_B_CPU0_SA_DQS_DP<4>")
	)
	(segment
		(start 304.394616 -275.154644)
		(end 304.378868 -275.154644)
		(width 0.16002)
		(layer "In2.Cu")
		(net "M_B_CPU0_SA_DQS_DP<4>")
	)
	(segment
		(start 302.107346 -276.30501)
		(end 300.579282 -276.30501)
		(width 0.18288)
		(layer "In2.Cu")
		(net "M_B_CPU0_SA_DQS_DP<4>")
	)
	(segment
		(start 302.532288 -275.880068)
		(end 302.51654 -275.880068)
		(width 0.16002)
		(layer "In2.Cu")
		(net "M_B_CPU0_SA_DQS_DP<4>")
	)
	(segment
		(start 307.69814 -275.880068)
		(end 307.669946 -275.851874)
		(width 0.16002)
		(layer "In2.Cu")
		(net "M_B_CPU0_SA_DQS_DP<4>")
	)
	(segment
		(start 299.93336 -275.659088)
		(end 299.481748 -275.659088)
		(width 0.18288)
		(layer "In2.Cu")
		(net "M_B_CPU0_SA_DQS_DP<4>")
	)
	(segment
		(start 331.650086 -260.869684)
		(end 329.818746 -262.701024)
		(width 0.088646)
		(layer "In2.Cu")
		(net "M_B_CPU0_SA_DQS_DP<4>")
	)
	(segment
		(start 312.055256 -273.566636)
		(end 312.055256 -273.582892)
		(width 0.16002)
		(layer "In2.Cu")
		(net "M_B_CPU0_SA_DQS_DP<4>")
	)
	(segment
		(start 313.59094 -273.298666)
		(end 313.424824 -273.13255)
		(width 0.18288)
		(layer "In2.Cu")
		(net "M_B_CPU0_SA_DQS_DP<4>")
	)
	(segment
		(start 312.027062 -273.611086)
		(end 310.64073 -274.998688)
		(width 0.18288)
		(layer "In2.Cu")
		(net "M_B_CPU0_SA_DQS_DP<4>")
	)
	(segment
		(start 309.860188 -276.095968)
		(end 309.831994 -276.124162)
		(width 0.16002)
		(layer "In2.Cu")
		(net "M_B_CPU0_SA_DQS_DP<4>")
	)
	(segment
		(start 307.669946 -275.851874)
		(end 307.489606 -275.671534)
		(width 0.18288)
		(layer "In2.Cu")
		(net "M_B_CPU0_SA_DQS_DP<4>")
	)
	(segment
		(start 306.371498 -275.943314)
		(end 306.099718 -275.671534)
		(width 0.18288)
		(layer "In2.Cu")
		(net "M_B_CPU0_SA_DQS_DP<4>")
	)
	(segment
		(start 313.63539 -273.32686)
		(end 313.619134 -273.32686)
		(width 0.16002)
		(layer "In2.Cu")
		(net "M_B_CPU0_SA_DQS_DP<4>")
	)
	(segment
		(start 309.831994 -276.124162)
		(end 309.626254 -276.329902)
		(width 0.18288)
		(layer "In2.Cu")
		(net "M_B_CPU0_SA_DQS_DP<4>")
	)
	(segment
		(start 297.050968 -275.370036)
		(end 296.850816 -275.169884)
		(width 0.16002)
		(layer "In2.Cu")
		(net "M_B_CPU0_SA_DQS_DP<4>")
	)
	(segment
		(start 298.531026 -275.662898)
		(end 297.328082 -275.662898)
		(width 0.18288)
		(layer "In2.Cu")
		(net "M_B_CPU0_SA_DQS_DP<4>")
	)
	(segment
		(start 325.653146 -264.358882)
		(end 322.790566 -265.5443)
		(width 0.18288)
		(layer "In2.Cu")
		(net "M_B_CPU0_SA_DQS_DP<4>")
	)
	(segment
		(start 295.785794 -275.29409)
		(end 295.126918 -275.29409)
		(width 0.18288)
		(layer "In2.Cu")
		(net "M_B_CPU0_SA_DQS_DP<4>")
	)
	(segment
		(start 300.398434 -276.124162)
		(end 300.37024 -276.095968)
		(width 0.16002)
		(layer "In2.Cu")
		(net "M_B_CPU0_SA_DQS_DP<4>")
	)
	(segment
		(start 306.099718 -275.671534)
		(end 304.895758 -275.671534)
		(width 0.18288)
		(layer "In2.Cu")
		(net "M_B_CPU0_SA_DQS_DP<4>")
	)
	(segment
		(start 307.713888 -275.880068)
		(end 307.69814 -275.880068)
		(width 0.16002)
		(layer "In2.Cu")
		(net "M_B_CPU0_SA_DQS_DP<4>")
	)
	(segment
		(start 298.809918 -275.94179)
		(end 298.531026 -275.662898)
		(width 0.18288)
		(layer "In2.Cu")
		(net "M_B_CPU0_SA_DQS_DP<4>")
	)
	(segment
		(start 336.757264 -260.431026)
		(end 336.476086 -260.712204)
		(width 0.088646)
		(layer "In2.Cu")
		(net "M_B_CPU0_SA_DQS_DP<4>")
	)
	(segment
		(start 300.15434 -275.880068)
		(end 300.126146 -275.851874)
		(width 0.16002)
		(layer "In2.Cu")
		(net "M_B_CPU0_SA_DQS_DP<4>")
	)
	(segment
		(start 309.626254 -276.329902)
		(end 308.147974 -276.329902)
		(width 0.18288)
		(layer "In2.Cu")
		(net "M_B_CPU0_SA_DQS_DP<4>")
	)
	(segment
		(start 304.378868 -275.154644)
		(end 304.350674 -275.12645)
		(width 0.16002)
		(layer "In2.Cu")
		(net "M_B_CPU0_SA_DQS_DP<4>")
	)
	(segment
		(start 300.170088 -275.880068)
		(end 300.15434 -275.880068)
		(width 0.16002)
		(layer "In2.Cu")
		(net "M_B_CPU0_SA_DQS_DP<4>")
	)
	(segment
		(start 302.316388 -276.08022)
		(end 302.316388 -276.095968)
		(width 0.16002)
		(layer "In2.Cu")
		(net "M_B_CPU0_SA_DQS_DP<4>")
	)
	(segment
		(start 313.835034 -273.526504)
		(end 313.63539 -273.32686)
		(width 0.16002)
		(layer "In2.Cu")
		(net "M_B_CPU0_SA_DQS_DP<4>")
	)
	(segment
		(start 336.164936 -260.804914)
		(end 335.967578 -260.804914)
		(width 0.088646)
		(layer "In2.Cu")
		(net "M_B_CPU0_SA_DQS_DP<4>")
	)
	(segment
		(start 307.942234 -276.124162)
		(end 307.91404 -276.095968)
		(width 0.16002)
		(layer "In2.Cu")
		(net "M_B_CPU0_SA_DQS_DP<4>")
	)
	(segment
		(start 328.962766 -263.014206)
		(end 326.997822 -263.014206)
		(width 0.18288)
		(layer "In2.Cu")
		(net "M_B_CPU0_SA_DQS_DP<4>")
	)
	(segment
		(start 314.587382 -273.74723)
		(end 314.039504 -273.74723)
		(width 0.18288)
		(layer "In2.Cu")
		(net "M_B_CPU0_SA_DQS_DP<4>")
	)
	(segment
		(start 310.06034 -275.880068)
		(end 309.860188 -276.08022)
		(width 0.16002)
		(layer "In2.Cu")
		(net "M_B_CPU0_SA_DQS_DP<4>")
	)
	(segment
		(start 337.135216 -260.430772)
		(end 336.757264 -260.431026)
		(width 0.088646)
		(layer "In2.Cu")
		(net "M_B_CPU0_SA_DQS_DP<4>")
	)
	(segment
		(start 312.25236 -273.369532)
		(end 312.055256 -273.566636)
		(width 0.16002)
		(layer "In2.Cu")
		(net "M_B_CPU0_SA_DQS_DP<4>")
	)
	(segment
		(start 299.481748 -275.659088)
		(end 299.199046 -275.94179)
		(width 0.18288)
		(layer "In2.Cu")
		(net "M_B_CPU0_SA_DQS_DP<4>")
	)
	(segment
		(start 307.91404 -276.08022)
		(end 307.713888 -275.880068)
		(width 0.16002)
		(layer "In2.Cu")
		(net "M_B_CPU0_SA_DQS_DP<4>")
	)
	(segment
		(start 329.105768 -262.894572)
		(end 328.986134 -263.014206)
		(width 0.088646)
		(layer "In2.Cu")
		(net "M_B_CPU0_SA_DQS_DP<4>")
	)
	(segment
		(start 329.35164 -262.894572)
		(end 329.105768 -262.894572)
		(width 0.088646)
		(layer "In2.Cu")
		(net "M_B_CPU0_SA_DQS_DP<4>")
	)
	(segment
		(start 304.895758 -275.671534)
		(end 304.622962 -275.398738)
		(width 0.18288)
		(layer "In2.Cu")
		(net "M_B_CPU0_SA_DQS_DP<4>")
	)
	(segment
		(start 296.806874 -275.14169)
		(end 296.631614 -274.96643)
		(width 0.18288)
		(layer "In2.Cu")
		(net "M_B_CPU0_SA_DQS_DP<4>")
	)
	(segment
		(start 300.579282 -276.30501)
		(end 300.398434 -276.124162)
		(width 0.18288)
		(layer "In2.Cu")
		(net "M_B_CPU0_SA_DQS_DP<4>")
	)
	(segment
		(start 313.619134 -273.32686)
		(end 313.59094 -273.298666)
		(width 0.16002)
		(layer "In2.Cu")
		(net "M_B_CPU0_SA_DQS_DP<4>")
	)
	(segment
		(start 295.126918 -275.29409)
		(end 294.904414 -275.516594)
		(width 0.18288)
		(layer "In2.Cu")
		(net "M_B_CPU0_SA_DQS_DP<4>")
	)
	(segment
		(start 312.505598 -273.13255)
		(end 312.29681 -273.341338)
		(width 0.18288)
		(layer "In2.Cu")
		(net "M_B_CPU0_SA_DQS_DP<4>")
	)
	(segment
		(start 299.199046 -275.94179)
		(end 298.809918 -275.94179)
		(width 0.18288)
		(layer "In2.Cu")
		(net "M_B_CPU0_SA_DQS_DP<4>")
	)
	(segment
		(start 310.104282 -275.851874)
		(end 310.076088 -275.880068)
		(width 0.16002)
		(layer "In2.Cu")
		(net "M_B_CPU0_SA_DQS_DP<4>")
	)
	(segment
		(start 312.29681 -273.341338)
		(end 312.268616 -273.369532)
		(width 0.16002)
		(layer "In2.Cu")
		(net "M_B_CPU0_SA_DQS_DP<4>")
	)
	(segment
		(start 310.64073 -274.998688)
		(end 310.416448 -275.539708)
		(width 0.18288)
		(layer "In2.Cu")
		(net "M_B_CPU0_SA_DQS_DP<4>")
	)
	(segment
		(start 300.37024 -276.095968)
		(end 300.37024 -276.08022)
		(width 0.16002)
		(layer "In2.Cu")
		(net "M_B_CPU0_SA_DQS_DP<4>")
	)
	(segment
		(start 322.790566 -265.5443)
		(end 314.587382 -273.74723)
		(width 0.18288)
		(layer "In2.Cu")
		(net "M_B_CPU0_SA_DQS_DP<4>")
	)
	(segment
		(start 309.860188 -276.08022)
		(end 309.860188 -276.095968)
		(width 0.16002)
		(layer "In2.Cu")
		(net "M_B_CPU0_SA_DQS_DP<4>")
	)
	(segment
		(start 326.997822 -263.014206)
		(end 325.653146 -264.358882)
		(width 0.18288)
		(layer "In2.Cu")
		(net "M_B_CPU0_SA_DQS_DP<4>")
	)
	(segment
		(start 336.175858 -260.804914)
		(end 336.165444 -260.804406)
		(width 0.088646)
		(layer "In2.Cu")
		(net "M_B_CPU0_SA_DQS_DP<4>")
	)
	(segment
		(start 304.594768 -275.354796)
		(end 304.394616 -275.154644)
		(width 0.16002)
		(layer "In2.Cu")
		(net "M_B_CPU0_SA_DQS_DP<4>")
	)
	(segment
		(start 329.818746 -262.701024)
		(end 329.35164 -262.894572)
		(width 0.088646)
		(layer "In2.Cu")
		(net "M_B_CPU0_SA_DQS_DP<4>")
	)
	(segment
		(start 310.416448 -275.539708)
		(end 310.104282 -275.851874)
		(width 0.18288)
		(layer "In2.Cu")
		(net "M_B_CPU0_SA_DQS_DP<4>")
	)
	(segment
		(start 297.079162 -275.413978)
		(end 297.050968 -275.385784)
		(width 0.16002)
		(layer "In2.Cu")
		(net "M_B_CPU0_SA_DQS_DP<4>")
	)
	(segment
		(start 306.725066 -275.943314)
		(end 306.371498 -275.943314)
		(width 0.18288)
		(layer "In2.Cu")
		(net "M_B_CPU0_SA_DQS_DP<4>")
	)
	(segment
		(start 304.251614 -275.02739)
		(end 303.957736 -275.02739)
		(width 0.18288)
		(layer "In2.Cu")
		(net "M_B_CPU0_SA_DQS_DP<4>")
	)
	(segment
		(start 296.835068 -275.169884)
		(end 296.806874 -275.14169)
		(width 0.16002)
		(layer "In2.Cu")
		(net "M_B_CPU0_SA_DQS_DP<4>")
	)
	(segment
		(start 314.039504 -273.74723)
		(end 313.863228 -273.570954)
		(width 0.18288)
		(layer "In2.Cu")
		(net "M_B_CPU0_SA_DQS_DP<4>")
	)
	(segment
		(start 303.32807 -275.657056)
		(end 302.7553 -275.657056)
		(width 0.18288)
		(layer "In2.Cu")
		(net "M_B_CPU0_SA_DQS_DP<4>")
	)
	(segment
		(start 304.350674 -275.12645)
		(end 304.251614 -275.02739)
		(width 0.18288)
		(layer "In2.Cu")
		(net "M_B_CPU0_SA_DQS_DP<4>")
	)
	(segment
		(start 334.973168 -260.92023)
		(end 334.97266 -260.920484)
		(width 0.088646)
		(layer "In2.Cu")
		(net "M_B_CPU0_SA_DQS_DP<4>")
	)
	(segment
		(start 302.51654 -275.880068)
		(end 302.316388 -276.08022)
		(width 0.16002)
		(layer "In2.Cu")
		(net "M_B_CPU0_SA_DQS_DP<4>")
	)
	(segment
		(start 302.316388 -276.095968)
		(end 302.288194 -276.124162)
		(width 0.16002)
		(layer "In2.Cu")
		(net "M_B_CPU0_SA_DQS_DP<4>")
	)
	(segment
		(start 300.37024 -276.08022)
		(end 300.170088 -275.880068)
		(width 0.16002)
		(layer "In2.Cu")
		(net "M_B_CPU0_SA_DQS_DP<4>")
	)
	(segment
		(start 304.594768 -275.370544)
		(end 304.594768 -275.354796)
		(width 0.16002)
		(layer "In2.Cu")
		(net "M_B_CPU0_SA_DQS_DP<4>")
	)
	(segment
		(start 308.147974 -276.329902)
		(end 307.942234 -276.124162)
		(width 0.18288)
		(layer "In2.Cu")
		(net "M_B_CPU0_SA_DQS_DP<4>")
	)
	(segment
		(start 312.055256 -273.582892)
		(end 312.027062 -273.611086)
		(width 0.16002)
		(layer "In2.Cu")
		(net "M_B_CPU0_SA_DQS_DP<4>")
	)
	(segment
		(start 297.328082 -275.662898)
		(end 297.079162 -275.413978)
		(width 0.18288)
		(layer "In2.Cu")
		(net "M_B_CPU0_SA_DQS_DP<4>")
	)
	(segment
		(start 307.91404 -276.095968)
		(end 307.91404 -276.08022)
		(width 0.16002)
		(layer "In2.Cu")
		(net "M_B_CPU0_SA_DQS_DP<4>")
	)
	(segment
		(start 304.622962 -275.398738)
		(end 304.594768 -275.370544)
		(width 0.16002)
		(layer "In2.Cu")
		(net "M_B_CPU0_SA_DQS_DP<4>")
	)
	(segment
		(start 302.7553 -275.657056)
		(end 302.560482 -275.851874)
		(width 0.18288)
		(layer "In2.Cu")
		(net "M_B_CPU0_SA_DQS_DP<4>")
	)
	(segment
		(start 300.126146 -275.851874)
		(end 299.93336 -275.659088)
		(width 0.18288)
		(layer "In2.Cu")
		(net "M_B_CPU0_SA_DQS_DP<4>")
	)
	(segment
		(start 296.113454 -274.96643)
		(end 295.785794 -275.29409)
		(width 0.18288)
		(layer "In2.Cu")
		(net "M_B_CPU0_SA_DQS_DP<4>")
	)
	(segment
		(start 297.050968 -275.385784)
		(end 297.050968 -275.370036)
		(width 0.16002)
		(layer "In2.Cu")
		(net "M_B_CPU0_SA_DQS_DP<4>")
	)
	(segment
		(start 296.850816 -275.169884)
		(end 296.835068 -275.169884)
		(width 0.16002)
		(layer "In2.Cu")
		(net "M_B_CPU0_SA_DQS_DP<4>")
	)
	(segment
		(start 336.165444 -260.804406)
		(end 336.164936 -260.804914)
		(width 0.088646)
		(layer "In2.Cu")
		(net "M_B_CPU0_SA_DQS_DP<4>")
	)
	(segment
		(start 313.835034 -273.54276)
		(end 313.835034 -273.526504)
		(width 0.16002)
		(layer "In2.Cu")
		(net "M_B_CPU0_SA_DQS_DP<4>")
	)
	(segment
		(start 312.268616 -273.369532)
		(end 312.25236 -273.369532)
		(width 0.16002)
		(layer "In2.Cu")
		(net "M_B_CPU0_SA_DQS_DP<4>")
	)
	(segment
		(start 307.489606 -275.671534)
		(end 306.996846 -275.671534)
		(width 0.18288)
		(layer "In2.Cu")
		(net "M_B_CPU0_SA_DQS_DP<4>")
	)
	(segment
		(start 328.986134 -263.014206)
		(end 328.962766 -263.014206)
		(width 0.088646)
		(layer "In2.Cu")
		(net "M_B_CPU0_SA_DQS_DP<4>")
	)
	(segment
		(start 313.863228 -273.570954)
		(end 313.835034 -273.54276)
		(width 0.16002)
		(layer "In2.Cu")
		(net "M_B_CPU0_SA_DQS_DP<4>")
	)
	(segment
		(start 302.288194 -276.124162)
		(end 302.107346 -276.30501)
		(width 0.18288)
		(layer "In2.Cu")
		(net "M_B_CPU0_SA_DQS_DP<4>")
	)
	(arc
		(start 336.38236 -260.755384)
		(mid 336.282693 -260.795085)
		(end 336.175858 -260.804914)
		(width 0.088646)
		(layer "In2.Cu")
		(net "M_B_CPU0_SA_DQS_DP<4>")
	)
	(arc
		(start 333.658464 -260.920484)
		(mid 333.375762 -260.996226)
		(end 333.09306 -260.920484)
		(width 0.088646)
		(layer "In2.Cu")
		(net "M_B_CPU0_SA_DQS_DP<4>")
	)
	(arc
		(start 335.967578 -260.804914)
		(mid 335.744964 -260.834233)
		(end 335.537556 -260.92023)
		(width 0.088646)
		(layer "In2.Cu")
		(net "M_B_CPU0_SA_DQS_DP<4>")
	)
	(arc
		(start 332.718664 -260.920484)
		(mid 332.435962 -260.996226)
		(end 332.15326 -260.920484)
		(width 0.088646)
		(layer "In2.Cu")
		(net "M_B_CPU0_SA_DQS_DP<4>")
	)
	(arc
		(start 335.537556 -260.92023)
		(mid 335.255362 -260.995786)
		(end 334.973168 -260.92023)
		(width 0.088646)
		(layer "In2.Cu")
		(net "M_B_CPU0_SA_DQS_DP<4>")
	)
	(arc
		(start 334.598264 -260.920484)
		(mid 334.315562 -260.996226)
		(end 334.03286 -260.920484)
		(width 0.088646)
		(layer "In2.Cu")
		(net "M_B_CPU0_SA_DQS_DP<4>")
	)
	(arc
		(start 336.476086 -260.712204)
		(mid 336.428233 -260.731645)
		(end 336.38236 -260.755384)
		(width 0.088646)
		(layer "In2.Cu")
		(net "M_B_CPU0_SA_DQS_DP<4>")
	)
	(arc
		(start 334.97266 -260.920484)
		(mid 334.785462 -260.870341)
		(end 334.598264 -260.920484)
		(width 0.088646)
		(layer "In2.Cu")
		(net "M_B_CPU0_SA_DQS_DP<4>")
	)
	(arc
		(start 334.03286 -260.920484)
		(mid 333.845662 -260.870341)
		(end 333.658464 -260.920484)
		(width 0.088646)
		(layer "In2.Cu")
		(net "M_B_CPU0_SA_DQS_DP<4>")
	)
	(arc
		(start 333.09306 -260.920484)
		(mid 332.905862 -260.870341)
		(end 332.718664 -260.920484)
		(width 0.088646)
		(layer "In2.Cu")
		(net "M_B_CPU0_SA_DQS_DP<4>")
	)
	(arc
		(start 332.15326 -260.920484)
		(mid 332.062999 -260.882787)
		(end 331.966062 -260.869684)
		(width 0.088646)
		(layer "In2.Cu")
		(net "M_B_CPU0_SA_DQS_DP<4>")
	)
	(segment
		(start 289.477958 -285.291784)
		(end 289.240976 -285.291784)
		(width 0.101854)
		(layer "F.Cu")
		(net "M_B_CPU0_SA_DQS_DP<3>")
	)
	(segment
		(start 287.054798 -284.605476)
		(end 286.793686 -284.866588)
		(width 0.20066)
		(layer "F.Cu")
		(net "M_B_CPU0_SA_DQS_DP<3>")
	)
	(segment
		(start 293.250874 -284.866588)
		(end 292.989762 -284.605476)
		(width 0.20066)
		(layer "F.Cu")
		(net "M_B_CPU0_SA_DQS_DP<3>")
	)
	(segment
		(start 293.799514 -284.866588)
		(end 293.250874 -284.866588)
		(width 0.20066)
		(layer "F.Cu")
		(net "M_B_CPU0_SA_DQS_DP<3>")
	)
	(segment
		(start 292.295834 -285.030672)
		(end 291.969952 -285.030672)
		(width 0.20066)
		(layer "F.Cu")
		(net "M_B_CPU0_SA_DQS_DP<3>")
	)
	(segment
		(start 288.742882 -285.030672)
		(end 288.115756 -285.030672)
		(width 0.20066)
		(layer "F.Cu")
		(net "M_B_CPU0_SA_DQS_DP<3>")
	)
	(segment
		(start 289.240976 -285.291784)
		(end 289.231578 -285.301182)
		(width 0.101854)
		(layer "F.Cu")
		(net "M_B_CPU0_SA_DQS_DP<3>")
	)
	(segment
		(start 287.47974 -284.605476)
		(end 287.054798 -284.605476)
		(width 0.20066)
		(layer "F.Cu")
		(net "M_B_CPU0_SA_DQS_DP<3>")
	)
	(segment
		(start 288.115756 -285.030672)
		(end 287.47974 -284.605476)
		(width 0.20066)
		(layer "F.Cu")
		(net "M_B_CPU0_SA_DQS_DP<3>")
	)
	(segment
		(start 291.233352 -285.291784)
		(end 289.477958 -285.291784)
		(width 0.1016)
		(layer "F.Cu")
		(net "M_B_CPU0_SA_DQS_DP<3>")
	)
	(segment
		(start 292.989762 -284.605476)
		(end 292.72103 -284.605476)
		(width 0.20066)
		(layer "F.Cu")
		(net "M_B_CPU0_SA_DQS_DP<3>")
	)
	(segment
		(start 291.969952 -285.030672)
		(end 291.70884 -285.291784)
		(width 0.20066)
		(layer "F.Cu")
		(net "M_B_CPU0_SA_DQS_DP<3>")
	)
	(segment
		(start 289.231578 -285.301182)
		(end 289.013392 -285.301182)
		(width 0.20066)
		(layer "F.Cu")
		(net "M_B_CPU0_SA_DQS_DP<3>")
	)
	(segment
		(start 340.424516 -262.336534)
		(end 340.424516 -262.87222)
		(width 0.20066)
		(layer "F.Cu")
		(net "M_B_CPU0_SA_DQS_DP<3>")
	)
	(segment
		(start 289.013392 -285.301182)
		(end 288.742882 -285.030672)
		(width 0.20066)
		(layer "F.Cu")
		(net "M_B_CPU0_SA_DQS_DP<3>")
	)
	(segment
		(start 292.72103 -284.605476)
		(end 292.295834 -285.030672)
		(width 0.20066)
		(layer "F.Cu")
		(net "M_B_CPU0_SA_DQS_DP<3>")
	)
	(segment
		(start 286.793686 -284.866588)
		(end 286.255714 -284.866588)
		(width 0.20066)
		(layer "F.Cu")
		(net "M_B_CPU0_SA_DQS_DP<3>")
	)
	(segment
		(start 291.556694 -285.291784)
		(end 291.233352 -285.291784)
		(width 0.101854)
		(layer "F.Cu")
		(net "M_B_CPU0_SA_DQS_DP<3>")
	)
	(segment
		(start 291.70884 -285.291784)
		(end 291.556694 -285.291784)
		(width 0.20066)
		(layer "F.Cu")
		(net "M_B_CPU0_SA_DQS_DP<3>")
	)
	(segment
		(start 340.424516 -262.87222)
		(end 340.424262 -262.872474)
		(width 0.20066)
		(layer "F.Cu")
		(net "M_B_CPU0_SA_DQS_DP<3>")
	)
	(segment
		(start 294.904414 -284.866588)
		(end 293.799514 -284.866588)
		(width 0.20066)
		(layer "F.Cu")
		(net "M_B_CPU0_SA_DQS_DP<3>")
	)
	(segment
		(start 295.185592 -284.58541)
		(end 294.904414 -284.866588)
		(width 0.18288)
		(layer "In4.Cu")
		(net "M_B_CPU0_SA_DQS_DP<3>")
	)
	(segment
		(start 295.831768 -284.58541)
		(end 295.185592 -284.58541)
		(width 0.18288)
		(layer "In4.Cu")
		(net "M_B_CPU0_SA_DQS_DP<3>")
	)
	(segment
		(start 297.504358 -284.40253)
		(end 296.014648 -284.40253)
		(width 0.18288)
		(layer "In4.Cu")
		(net "M_B_CPU0_SA_DQS_DP<3>")
	)
	(segment
		(start 331.167232 -263.518396)
		(end 330.82357 -263.518396)
		(width 0.088646)
		(layer "In4.Cu")
		(net "M_B_CPU0_SA_DQS_DP<3>")
	)
	(segment
		(start 303.675034 -282.513532)
		(end 303.312322 -283.389324)
		(width 0.18288)
		(layer "In4.Cu")
		(net "M_B_CPU0_SA_DQS_DP<3>")
	)
	(segment
		(start 303.312322 -283.389324)
		(end 302.857916 -283.84373)
		(width 0.18288)
		(layer "In4.Cu")
		(net "M_B_CPU0_SA_DQS_DP<3>")
	)
	(segment
		(start 338.26196 -263.361932)
		(end 338.26196 -263.362186)
		(width 0.088646)
		(layer "In4.Cu")
		(net "M_B_CPU0_SA_DQS_DP<3>")
	)
	(segment
		(start 326.325992 -264.21715)
		(end 316.554358 -273.98853)
		(width 0.18288)
		(layer "In4.Cu")
		(net "M_B_CPU0_SA_DQS_DP<3>")
	)
	(segment
		(start 299.177964 -285.292038)
		(end 298.81068 -285.292038)
		(width 0.18288)
		(layer "In4.Cu")
		(net "M_B_CPU0_SA_DQS_DP<3>")
	)
	(segment
		(start 340.083902 -262.96239)
		(end 339.658706 -263.204198)
		(width 0.088646)
		(layer "In4.Cu")
		(net "M_B_CPU0_SA_DQS_DP<3>")
	)
	(segment
		(start 308.301136 -280.699972)
		(end 306.200048 -281.57043)
		(width 0.18288)
		(layer "In4.Cu")
		(net "M_B_CPU0_SA_DQS_DP<3>")
	)
	(segment
		(start 313.881516 -275.0947)
		(end 313.689746 -275.306536)
		(width 0.18288)
		(layer "In4.Cu")
		(net "M_B_CPU0_SA_DQS_DP<3>")
	)
	(segment
		(start 302.857916 -283.84373)
		(end 300.5963 -284.780482)
		(width 0.18288)
		(layer "In4.Cu")
		(net "M_B_CPU0_SA_DQS_DP<3>")
	)
	(segment
		(start 300.011592 -284.780482)
		(end 299.46219 -285.007812)
		(width 0.18288)
		(layer "In4.Cu")
		(net "M_B_CPU0_SA_DQS_DP<3>")
	)
	(segment
		(start 339.397086 -263.238996)
		(end 339.39226 -263.241536)
		(width 0.088646)
		(layer "In4.Cu")
		(net "M_B_CPU0_SA_DQS_DP<3>")
	)
	(segment
		(start 331.591158 -263.337294)
		(end 331.348334 -263.337294)
		(width 0.088646)
		(layer "In4.Cu")
		(net "M_B_CPU0_SA_DQS_DP<3>")
	)
	(segment
		(start 300.5963 -284.780482)
		(end 300.011592 -284.780482)
		(width 0.18288)
		(layer "In4.Cu")
		(net "M_B_CPU0_SA_DQS_DP<3>")
	)
	(segment
		(start 304.455322 -281.57043)
		(end 304.002948 -282.022804)
		(width 0.18288)
		(layer "In4.Cu")
		(net "M_B_CPU0_SA_DQS_DP<3>")
	)
	(segment
		(start 312.433208 -277.761192)
		(end 311.446926 -278.420322)
		(width 0.18288)
		(layer "In4.Cu")
		(net "M_B_CPU0_SA_DQS_DP<3>")
	)
	(segment
		(start 304.002948 -282.022804)
		(end 303.675034 -282.513532)
		(width 0.18288)
		(layer "In4.Cu")
		(net "M_B_CPU0_SA_DQS_DP<3>")
	)
	(segment
		(start 339.454236 -263.245854)
		(end 339.397086 -263.238996)
		(width 0.088646)
		(layer "In4.Cu")
		(net "M_B_CPU0_SA_DQS_DP<3>")
	)
	(segment
		(start 313.689746 -275.306536)
		(end 312.842148 -277.352252)
		(width 0.18288)
		(layer "In4.Cu")
		(net "M_B_CPU0_SA_DQS_DP<3>")
	)
	(segment
		(start 298.126404 -285.024576)
		(end 297.504358 -284.40253)
		(width 0.18288)
		(layer "In4.Cu")
		(net "M_B_CPU0_SA_DQS_DP<3>")
	)
	(segment
		(start 299.46219 -285.007812)
		(end 299.177964 -285.292038)
		(width 0.18288)
		(layer "In4.Cu")
		(net "M_B_CPU0_SA_DQS_DP<3>")
	)
	(segment
		(start 298.81068 -285.292038)
		(end 298.543218 -285.024576)
		(width 0.18288)
		(layer "In4.Cu")
		(net "M_B_CPU0_SA_DQS_DP<3>")
	)
	(segment
		(start 339.39226 -263.241536)
		(end 339.03666 -263.241536)
		(width 0.088646)
		(layer "In4.Cu")
		(net "M_B_CPU0_SA_DQS_DP<3>")
	)
	(segment
		(start 311.446926 -278.420322)
		(end 309.967884 -279.033224)
		(width 0.18288)
		(layer "In4.Cu")
		(net "M_B_CPU0_SA_DQS_DP<3>")
	)
	(segment
		(start 316.554358 -273.98853)
		(end 313.881516 -275.0947)
		(width 0.18288)
		(layer "In4.Cu")
		(net "M_B_CPU0_SA_DQS_DP<3>")
	)
	(segment
		(start 330.724002 -263.57834)
		(end 327.86701 -263.57834)
		(width 0.18288)
		(layer "In4.Cu")
		(net "M_B_CPU0_SA_DQS_DP<3>")
	)
	(segment
		(start 296.014648 -284.40253)
		(end 295.831768 -284.58541)
		(width 0.18288)
		(layer "In4.Cu")
		(net "M_B_CPU0_SA_DQS_DP<3>")
	)
	(segment
		(start 330.763626 -263.57834)
		(end 330.724002 -263.57834)
		(width 0.088646)
		(layer "In4.Cu")
		(net "M_B_CPU0_SA_DQS_DP<3>")
	)
	(segment
		(start 331.348334 -263.337294)
		(end 331.167232 -263.518396)
		(width 0.088646)
		(layer "In4.Cu")
		(net "M_B_CPU0_SA_DQS_DP<3>")
	)
	(segment
		(start 309.967884 -279.033224)
		(end 308.301136 -280.699972)
		(width 0.18288)
		(layer "In4.Cu")
		(net "M_B_CPU0_SA_DQS_DP<3>")
	)
	(segment
		(start 306.200048 -281.57043)
		(end 304.455322 -281.57043)
		(width 0.18288)
		(layer "In4.Cu")
		(net "M_B_CPU0_SA_DQS_DP<3>")
	)
	(segment
		(start 327.86701 -263.57834)
		(end 326.325992 -264.21715)
		(width 0.18288)
		(layer "In4.Cu")
		(net "M_B_CPU0_SA_DQS_DP<3>")
	)
	(segment
		(start 298.543218 -285.024576)
		(end 298.126404 -285.024576)
		(width 0.18288)
		(layer "In4.Cu")
		(net "M_B_CPU0_SA_DQS_DP<3>")
	)
	(segment
		(start 312.842148 -277.352252)
		(end 312.433208 -277.761192)
		(width 0.18288)
		(layer "In4.Cu")
		(net "M_B_CPU0_SA_DQS_DP<3>")
	)
	(segment
		(start 330.82357 -263.518396)
		(end 330.763626 -263.57834)
		(width 0.088646)
		(layer "In4.Cu")
		(net "M_B_CPU0_SA_DQS_DP<3>")
	)
	(segment
		(start 339.03666 -263.241536)
		(end 338.81314 -263.370314)
		(width 0.088646)
		(layer "In4.Cu")
		(net "M_B_CPU0_SA_DQS_DP<3>")
	)
	(arc
		(start 337.887564 -263.362186)
		(mid 337.604862 -263.437928)
		(end 337.32216 -263.362186)
		(width 0.088646)
		(layer "In4.Cu")
		(net "M_B_CPU0_SA_DQS_DP<3>")
	)
	(arc
		(start 334.50276 -263.362186)
		(mid 334.315562 -263.312043)
		(end 334.128364 -263.362186)
		(width 0.088646)
		(layer "In4.Cu")
		(net "M_B_CPU0_SA_DQS_DP<3>")
	)
	(arc
		(start 338.26196 -263.362186)
		(mid 338.074762 -263.312043)
		(end 337.887564 -263.362186)
		(width 0.088646)
		(layer "In4.Cu")
		(net "M_B_CPU0_SA_DQS_DP<3>")
	)
	(arc
		(start 333.188564 -263.362186)
		(mid 332.905862 -263.437928)
		(end 332.62316 -263.362186)
		(width 0.088646)
		(layer "In4.Cu")
		(net "M_B_CPU0_SA_DQS_DP<3>")
	)
	(arc
		(start 334.128364 -263.362186)
		(mid 333.845662 -263.437928)
		(end 333.56296 -263.362186)
		(width 0.088646)
		(layer "In4.Cu")
		(net "M_B_CPU0_SA_DQS_DP<3>")
	)
	(arc
		(start 335.44256 -263.362186)
		(mid 335.255362 -263.312043)
		(end 335.068164 -263.362186)
		(width 0.088646)
		(layer "In4.Cu")
		(net "M_B_CPU0_SA_DQS_DP<3>")
	)
	(arc
		(start 337.32216 -263.362186)
		(mid 337.134962 -263.312043)
		(end 336.947764 -263.362186)
		(width 0.088646)
		(layer "In4.Cu")
		(net "M_B_CPU0_SA_DQS_DP<3>")
	)
	(arc
		(start 332.62316 -263.362186)
		(mid 332.435962 -263.312043)
		(end 332.248764 -263.362186)
		(width 0.088646)
		(layer "In4.Cu")
		(net "M_B_CPU0_SA_DQS_DP<3>")
	)
	(arc
		(start 336.38236 -263.362186)
		(mid 336.195162 -263.312043)
		(end 336.007964 -263.362186)
		(width 0.088646)
		(layer "In4.Cu")
		(net "M_B_CPU0_SA_DQS_DP<3>")
	)
	(arc
		(start 339.658706 -263.204198)
		(mid 339.559864 -263.241708)
		(end 339.454236 -263.245854)
		(width 0.088646)
		(layer "In4.Cu")
		(net "M_B_CPU0_SA_DQS_DP<3>")
	)
	(arc
		(start 340.424262 -262.872474)
		(mid 340.248241 -262.895311)
		(end 340.083902 -262.96239)
		(width 0.088646)
		(layer "In4.Cu")
		(net "M_B_CPU0_SA_DQS_DP<3>")
	)
	(arc
		(start 335.068164 -263.362186)
		(mid 334.785462 -263.437928)
		(end 334.50276 -263.362186)
		(width 0.088646)
		(layer "In4.Cu")
		(net "M_B_CPU0_SA_DQS_DP<3>")
	)
	(arc
		(start 332.248764 -263.362186)
		(mid 331.966062 -263.437928)
		(end 331.68336 -263.362186)
		(width 0.088646)
		(layer "In4.Cu")
		(net "M_B_CPU0_SA_DQS_DP<3>")
	)
	(arc
		(start 331.68336 -263.362186)
		(mid 331.638902 -263.34367)
		(end 331.591158 -263.337294)
		(width 0.088646)
		(layer "In4.Cu")
		(net "M_B_CPU0_SA_DQS_DP<3>")
	)
	(arc
		(start 333.56296 -263.362186)
		(mid 333.375762 -263.312043)
		(end 333.188564 -263.362186)
		(width 0.088646)
		(layer "In4.Cu")
		(net "M_B_CPU0_SA_DQS_DP<3>")
	)
	(arc
		(start 338.81314 -263.370314)
		(mid 338.536475 -263.437785)
		(end 338.26196 -263.361932)
		(width 0.088646)
		(layer "In4.Cu")
		(net "M_B_CPU0_SA_DQS_DP<3>")
	)
	(arc
		(start 336.007964 -263.362186)
		(mid 335.725262 -263.437928)
		(end 335.44256 -263.362186)
		(width 0.088646)
		(layer "In4.Cu")
		(net "M_B_CPU0_SA_DQS_DP<3>")
	)
	(arc
		(start 336.947764 -263.362186)
		(mid 336.665062 -263.437928)
		(end 336.38236 -263.362186)
		(width 0.088646)
		(layer "In4.Cu")
		(net "M_B_CPU0_SA_DQS_DP<3>")
	)
	(segment
		(start 291.233352 -294.641778)
		(end 289.477958 -294.641778)
		(width 0.1016)
		(layer "F.Cu")
		(net "M_B_CPU0_SA_DQS_DP<2>")
	)
	(segment
		(start 289.477958 -294.641778)
		(end 289.240976 -294.641778)
		(width 0.101854)
		(layer "F.Cu")
		(net "M_B_CPU0_SA_DQS_DP<2>")
	)
	(segment
		(start 292.295834 -294.380666)
		(end 291.969952 -294.380666)
		(width 0.20066)
		(layer "F.Cu")
		(net "M_B_CPU0_SA_DQS_DP<2>")
	)
	(segment
		(start 293.799514 -294.216582)
		(end 293.250874 -294.216582)
		(width 0.20066)
		(layer "F.Cu")
		(net "M_B_CPU0_SA_DQS_DP<2>")
	)
	(segment
		(start 288.115756 -294.380666)
		(end 287.47974 -293.95547)
		(width 0.20066)
		(layer "F.Cu")
		(net "M_B_CPU0_SA_DQS_DP<2>")
	)
	(segment
		(start 287.47974 -293.95547)
		(end 287.054798 -293.95547)
		(width 0.20066)
		(layer "F.Cu")
		(net "M_B_CPU0_SA_DQS_DP<2>")
	)
	(segment
		(start 292.72103 -293.95547)
		(end 292.295834 -294.380666)
		(width 0.20066)
		(layer "F.Cu")
		(net "M_B_CPU0_SA_DQS_DP<2>")
	)
	(segment
		(start 291.969952 -294.380666)
		(end 291.70884 -294.641778)
		(width 0.20066)
		(layer "F.Cu")
		(net "M_B_CPU0_SA_DQS_DP<2>")
	)
	(segment
		(start 289.231578 -294.651176)
		(end 289.013392 -294.651176)
		(width 0.20066)
		(layer "F.Cu")
		(net "M_B_CPU0_SA_DQS_DP<2>")
	)
	(segment
		(start 291.556694 -294.641778)
		(end 291.233352 -294.641778)
		(width 0.101854)
		(layer "F.Cu")
		(net "M_B_CPU0_SA_DQS_DP<2>")
	)
	(segment
		(start 287.054798 -293.95547)
		(end 286.793686 -294.216582)
		(width 0.20066)
		(layer "F.Cu")
		(net "M_B_CPU0_SA_DQS_DP<2>")
	)
	(segment
		(start 286.793686 -294.216582)
		(end 286.255714 -294.216582)
		(width 0.20066)
		(layer "F.Cu")
		(net "M_B_CPU0_SA_DQS_DP<2>")
	)
	(segment
		(start 288.742882 -294.380666)
		(end 288.115756 -294.380666)
		(width 0.20066)
		(layer "F.Cu")
		(net "M_B_CPU0_SA_DQS_DP<2>")
	)
	(segment
		(start 289.240976 -294.641778)
		(end 289.231578 -294.651176)
		(width 0.101854)
		(layer "F.Cu")
		(net "M_B_CPU0_SA_DQS_DP<2>")
	)
	(segment
		(start 289.013392 -294.651176)
		(end 288.742882 -294.380666)
		(width 0.20066)
		(layer "F.Cu")
		(net "M_B_CPU0_SA_DQS_DP<2>")
	)
	(segment
		(start 292.989762 -293.95547)
		(end 292.72103 -293.95547)
		(width 0.20066)
		(layer "F.Cu")
		(net "M_B_CPU0_SA_DQS_DP<2>")
	)
	(segment
		(start 294.904414 -294.216582)
		(end 293.799514 -294.216582)
		(width 0.20066)
		(layer "F.Cu")
		(net "M_B_CPU0_SA_DQS_DP<2>")
	)
	(segment
		(start 337.134962 -264.778236)
		(end 337.134962 -265.314176)
		(width 0.20066)
		(layer "F.Cu")
		(net "M_B_CPU0_SA_DQS_DP<2>")
	)
	(segment
		(start 291.70884 -294.641778)
		(end 291.556694 -294.641778)
		(width 0.20066)
		(layer "F.Cu")
		(net "M_B_CPU0_SA_DQS_DP<2>")
	)
	(segment
		(start 293.250874 -294.216582)
		(end 292.989762 -293.95547)
		(width 0.20066)
		(layer "F.Cu")
		(net "M_B_CPU0_SA_DQS_DP<2>")
	)
	(segment
		(start 304.717704 -292.128448)
		(end 304.68951 -292.156642)
		(width 0.16002)
		(layer "In2.Cu")
		(net "M_B_CPU0_SA_DQS_DP<2>")
	)
	(segment
		(start 312.062368 -285.496)
		(end 312.062368 -285.512256)
		(width 0.16002)
		(layer "In2.Cu")
		(net "M_B_CPU0_SA_DQS_DP<2>")
	)
	(segment
		(start 337.134962 -265.314176)
		(end 336.757264 -265.314176)
		(width 0.088646)
		(layer "In2.Cu")
		(net "M_B_CPU0_SA_DQS_DP<2>")
	)
	(segment
		(start 328.652378 -269.093696)
		(end 328.401934 -269.197328)
		(width 0.18288)
		(layer "In2.Cu")
		(net "M_B_CPU0_SA_DQS_DP<2>")
	)
	(segment
		(start 307.307488 -288.976816)
		(end 307.307488 -290.1061)
		(width 0.18288)
		(layer "In2.Cu")
		(net "M_B_CPU0_SA_DQS_DP<2>")
	)
	(segment
		(start 297.079162 -294.113966)
		(end 297.050968 -294.085772)
		(width 0.16002)
		(layer "In2.Cu")
		(net "M_B_CPU0_SA_DQS_DP<2>")
	)
	(segment
		(start 310.03113 -286.990282)
		(end 310.015382 -286.990282)
		(width 0.16002)
		(layer "In2.Cu")
		(net "M_B_CPU0_SA_DQS_DP<2>")
	)
	(segment
		(start 297.050968 -294.070024)
		(end 296.850816 -293.869872)
		(width 0.16002)
		(layer "In2.Cu")
		(net "M_B_CPU0_SA_DQS_DP<2>")
	)
	(segment
		(start 310.642762 -286.37865)
		(end 310.059324 -286.962088)
		(width 0.18288)
		(layer "In2.Cu")
		(net "M_B_CPU0_SA_DQS_DP<2>")
	)
	(segment
		(start 298.510198 -294.374316)
		(end 297.339512 -294.374316)
		(width 0.18288)
		(layer "In2.Cu")
		(net "M_B_CPU0_SA_DQS_DP<2>")
	)
	(segment
		(start 302.316388 -294.795956)
		(end 302.288194 -294.82415)
		(width 0.16002)
		(layer "In2.Cu")
		(net "M_B_CPU0_SA_DQS_DP<2>")
	)
	(segment
		(start 306.284122 -291.52596)
		(end 305.889152 -291.92093)
		(width 0.18288)
		(layer "In2.Cu")
		(net "M_B_CPU0_SA_DQS_DP<2>")
	)
	(segment
		(start 312.062368 -285.512256)
		(end 312.034174 -285.54045)
		(width 0.16002)
		(layer "In2.Cu")
		(net "M_B_CPU0_SA_DQS_DP<2>")
	)
	(segment
		(start 302.532288 -294.580056)
		(end 302.51654 -294.580056)
		(width 0.16002)
		(layer "In2.Cu")
		(net "M_B_CPU0_SA_DQS_DP<2>")
	)
	(segment
		(start 304.68951 -292.156642)
		(end 304.673254 -292.156642)
		(width 0.16002)
		(layer "In2.Cu")
		(net "M_B_CPU0_SA_DQS_DP<2>")
	)
	(segment
		(start 302.51654 -294.580056)
		(end 302.316388 -294.780208)
		(width 0.16002)
		(layer "In2.Cu")
		(net "M_B_CPU0_SA_DQS_DP<2>")
	)
	(segment
		(start 296.835068 -293.869872)
		(end 296.806874 -293.841678)
		(width 0.16002)
		(layer "In2.Cu")
		(net "M_B_CPU0_SA_DQS_DP<2>")
	)
	(segment
		(start 310.015382 -286.990282)
		(end 309.81523 -287.190434)
		(width 0.16002)
		(layer "In2.Cu")
		(net "M_B_CPU0_SA_DQS_DP<2>")
	)
	(segment
		(start 314.831222 -284.10789)
		(end 314.463684 -284.10789)
		(width 0.18288)
		(layer "In2.Cu")
		(net "M_B_CPU0_SA_DQS_DP<2>")
	)
	(segment
		(start 312.262012 -285.296356)
		(end 312.062368 -285.496)
		(width 0.16002)
		(layer "In2.Cu")
		(net "M_B_CPU0_SA_DQS_DP<2>")
	)
	(segment
		(start 302.288194 -294.82415)
		(end 302.082454 -295.02989)
		(width 0.18288)
		(layer "In2.Cu")
		(net "M_B_CPU0_SA_DQS_DP<2>")
	)
	(segment
		(start 299.532294 -294.367712)
		(end 299.258482 -294.641524)
		(width 0.18288)
		(layer "In2.Cu")
		(net "M_B_CPU0_SA_DQS_DP<2>")
	)
	(segment
		(start 300.37024 -294.795956)
		(end 300.37024 -294.780208)
		(width 0.16002)
		(layer "In2.Cu")
		(net "M_B_CPU0_SA_DQS_DP<2>")
	)
	(segment
		(start 306.512468 -291.281866)
		(end 306.312316 -291.482018)
		(width 0.16002)
		(layer "In2.Cu")
		(net "M_B_CPU0_SA_DQS_DP<2>")
	)
	(segment
		(start 307.307488 -290.1061)
		(end 307.026564 -290.783264)
		(width 0.18288)
		(layer "In2.Cu")
		(net "M_B_CPU0_SA_DQS_DP<2>")
	)
	(segment
		(start 312.604912 -284.969712)
		(end 312.306462 -285.268162)
		(width 0.18288)
		(layer "In2.Cu")
		(net "M_B_CPU0_SA_DQS_DP<2>")
	)
	(segment
		(start 302.082454 -295.02989)
		(end 300.604174 -295.02989)
		(width 0.18288)
		(layer "In2.Cu")
		(net "M_B_CPU0_SA_DQS_DP<2>")
	)
	(segment
		(start 333.658464 -265.803888)
		(end 333.657956 -265.80338)
		(width 0.088646)
		(layer "In2.Cu")
		(net "M_B_CPU0_SA_DQS_DP<2>")
	)
	(segment
		(start 295.611296 -293.958264)
		(end 295.162732 -293.958264)
		(width 0.18288)
		(layer "In2.Cu")
		(net "M_B_CPU0_SA_DQS_DP<2>")
	)
	(segment
		(start 330.622148 -267.123926)
		(end 328.652378 -269.093696)
		(width 0.18288)
		(layer "In2.Cu")
		(net "M_B_CPU0_SA_DQS_DP<2>")
	)
	(segment
		(start 306.528216 -291.281866)
		(end 306.512468 -291.281866)
		(width 0.16002)
		(layer "In2.Cu")
		(net "M_B_CPU0_SA_DQS_DP<2>")
	)
	(segment
		(start 313.915298 -284.656276)
		(end 313.887104 -284.68447)
		(width 0.16002)
		(layer "In2.Cu")
		(net "M_B_CPU0_SA_DQS_DP<2>")
	)
	(segment
		(start 305.889152 -291.92093)
		(end 304.925222 -291.92093)
		(width 0.18288)
		(layer "In2.Cu")
		(net "M_B_CPU0_SA_DQS_DP<2>")
	)
	(segment
		(start 295.162732 -293.958264)
		(end 294.904414 -294.216582)
		(width 0.18288)
		(layer "In2.Cu")
		(net "M_B_CPU0_SA_DQS_DP<2>")
	)
	(segment
		(start 300.37024 -294.780208)
		(end 300.170088 -294.580056)
		(width 0.16002)
		(layer "In2.Cu")
		(net "M_B_CPU0_SA_DQS_DP<2>")
	)
	(segment
		(start 308.021482 -288.02076)
		(end 307.993288 -288.048954)
		(width 0.16002)
		(layer "In2.Cu")
		(net "M_B_CPU0_SA_DQS_DP<2>")
	)
	(segment
		(start 308.265576 -287.776666)
		(end 308.237382 -287.80486)
		(width 0.16002)
		(layer "In2.Cu")
		(net "M_B_CPU0_SA_DQS_DP<2>")
	)
	(segment
		(start 296.262044 -293.68877)
		(end 295.611296 -293.958264)
		(width 0.18288)
		(layer "In2.Cu")
		(net "M_B_CPU0_SA_DQS_DP<2>")
	)
	(segment
		(start 299.941996 -294.367712)
		(end 299.532294 -294.367712)
		(width 0.18288)
		(layer "In2.Cu")
		(net "M_B_CPU0_SA_DQS_DP<2>")
	)
	(segment
		(start 306.312316 -291.482018)
		(end 306.312316 -291.497766)
		(width 0.16002)
		(layer "In2.Cu")
		(net "M_B_CPU0_SA_DQS_DP<2>")
	)
	(segment
		(start 314.131198 -284.440376)
		(end 314.11545 -284.440376)
		(width 0.16002)
		(layer "In2.Cu")
		(net "M_B_CPU0_SA_DQS_DP<2>")
	)
	(segment
		(start 296.806874 -293.841678)
		(end 296.653966 -293.68877)
		(width 0.18288)
		(layer "In2.Cu")
		(net "M_B_CPU0_SA_DQS_DP<2>")
	)
	(segment
		(start 303.011586 -293.834566)
		(end 303.011586 -294.100758)
		(width 0.18288)
		(layer "In2.Cu")
		(net "M_B_CPU0_SA_DQS_DP<2>")
	)
	(segment
		(start 309.81523 -287.190434)
		(end 309.81523 -287.206182)
		(width 0.16002)
		(layer "In2.Cu")
		(net "M_B_CPU0_SA_DQS_DP<2>")
	)
	(segment
		(start 308.021482 -288.004504)
		(end 308.021482 -288.02076)
		(width 0.16002)
		(layer "In2.Cu")
		(net "M_B_CPU0_SA_DQS_DP<2>")
	)
	(segment
		(start 318.669924 -280.269188)
		(end 314.831222 -284.10789)
		(width 0.18288)
		(layer "In2.Cu")
		(net "M_B_CPU0_SA_DQS_DP<2>")
	)
	(segment
		(start 312.278268 -285.296356)
		(end 312.262012 -285.296356)
		(width 0.16002)
		(layer "In2.Cu")
		(net "M_B_CPU0_SA_DQS_DP<2>")
	)
	(segment
		(start 308.221126 -287.80486)
		(end 308.021482 -288.004504)
		(width 0.16002)
		(layer "In2.Cu")
		(net "M_B_CPU0_SA_DQS_DP<2>")
	)
	(segment
		(start 300.15434 -294.580056)
		(end 300.126146 -294.551862)
		(width 0.16002)
		(layer "In2.Cu")
		(net "M_B_CPU0_SA_DQS_DP<2>")
	)
	(segment
		(start 310.059324 -286.962088)
		(end 310.03113 -286.990282)
		(width 0.16002)
		(layer "In2.Cu")
		(net "M_B_CPU0_SA_DQS_DP<2>")
	)
	(segment
		(start 300.170088 -294.580056)
		(end 300.15434 -294.580056)
		(width 0.16002)
		(layer "In2.Cu")
		(net "M_B_CPU0_SA_DQS_DP<2>")
	)
	(segment
		(start 297.339512 -294.374316)
		(end 297.079162 -294.113966)
		(width 0.18288)
		(layer "In2.Cu")
		(net "M_B_CPU0_SA_DQS_DP<2>")
	)
	(segment
		(start 336.175858 -265.688064)
		(end 335.967578 -265.688064)
		(width 0.088646)
		(layer "In2.Cu")
		(net "M_B_CPU0_SA_DQS_DP<2>")
	)
	(segment
		(start 308.403752 -287.63849)
		(end 308.265576 -287.776666)
		(width 0.18288)
		(layer "In2.Cu")
		(net "M_B_CPU0_SA_DQS_DP<2>")
	)
	(segment
		(start 303.011586 -294.100758)
		(end 302.560482 -294.551862)
		(width 0.18288)
		(layer "In2.Cu")
		(net "M_B_CPU0_SA_DQS_DP<2>")
	)
	(segment
		(start 298.777406 -294.641524)
		(end 298.510198 -294.374316)
		(width 0.18288)
		(layer "In2.Cu")
		(net "M_B_CPU0_SA_DQS_DP<2>")
	)
	(segment
		(start 328.401934 -269.197328)
		(end 318.669924 -278.929338)
		(width 0.18288)
		(layer "In2.Cu")
		(net "M_B_CPU0_SA_DQS_DP<2>")
	)
	(segment
		(start 313.915298 -284.640528)
		(end 313.915298 -284.656276)
		(width 0.16002)
		(layer "In2.Cu")
		(net "M_B_CPU0_SA_DQS_DP<2>")
	)
	(segment
		(start 307.993288 -288.048954)
		(end 307.479446 -288.563304)
		(width 0.18288)
		(layer "In2.Cu")
		(net "M_B_CPU0_SA_DQS_DP<2>")
	)
	(segment
		(start 307.479446 -288.563304)
		(end 307.307488 -288.976816)
		(width 0.18288)
		(layer "In2.Cu")
		(net "M_B_CPU0_SA_DQS_DP<2>")
	)
	(segment
		(start 331.941932 -265.861038)
		(end 331.698092 -265.982958)
		(width 0.088646)
		(layer "In2.Cu")
		(net "M_B_CPU0_SA_DQS_DP<2>")
	)
	(segment
		(start 308.237382 -287.80486)
		(end 308.221126 -287.80486)
		(width 0.16002)
		(layer "In2.Cu")
		(net "M_B_CPU0_SA_DQS_DP<2>")
	)
	(segment
		(start 304.47361 -292.372542)
		(end 304.445416 -292.400736)
		(width 0.16002)
		(layer "In2.Cu")
		(net "M_B_CPU0_SA_DQS_DP<2>")
	)
	(segment
		(start 304.673254 -292.156642)
		(end 304.47361 -292.356286)
		(width 0.16002)
		(layer "In2.Cu")
		(net "M_B_CPU0_SA_DQS_DP<2>")
	)
	(segment
		(start 330.622148 -267.03909)
		(end 330.622148 -267.123926)
		(width 0.088646)
		(layer "In2.Cu")
		(net "M_B_CPU0_SA_DQS_DP<2>")
	)
	(segment
		(start 309.81523 -287.206182)
		(end 309.787036 -287.234376)
		(width 0.16002)
		(layer "In2.Cu")
		(net "M_B_CPU0_SA_DQS_DP<2>")
	)
	(segment
		(start 302.316388 -294.780208)
		(end 302.316388 -294.795956)
		(width 0.16002)
		(layer "In2.Cu")
		(net "M_B_CPU0_SA_DQS_DP<2>")
	)
	(segment
		(start 309.382922 -287.63849)
		(end 308.403752 -287.63849)
		(width 0.18288)
		(layer "In2.Cu")
		(net "M_B_CPU0_SA_DQS_DP<2>")
	)
	(segment
		(start 318.669924 -278.929338)
		(end 318.669924 -280.269188)
		(width 0.18288)
		(layer "In2.Cu")
		(net "M_B_CPU0_SA_DQS_DP<2>")
	)
	(segment
		(start 302.560482 -294.551862)
		(end 302.532288 -294.580056)
		(width 0.16002)
		(layer "In2.Cu")
		(net "M_B_CPU0_SA_DQS_DP<2>")
	)
	(segment
		(start 306.55641 -291.253672)
		(end 306.528216 -291.281866)
		(width 0.16002)
		(layer "In2.Cu")
		(net "M_B_CPU0_SA_DQS_DP<2>")
	)
	(segment
		(start 313.601862 -284.969712)
		(end 312.604912 -284.969712)
		(width 0.18288)
		(layer "In2.Cu")
		(net "M_B_CPU0_SA_DQS_DP<2>")
	)
	(segment
		(start 304.47361 -292.356286)
		(end 304.47361 -292.372542)
		(width 0.16002)
		(layer "In2.Cu")
		(net "M_B_CPU0_SA_DQS_DP<2>")
	)
	(segment
		(start 336.757264 -265.314176)
		(end 336.476086 -265.595354)
		(width 0.088646)
		(layer "In2.Cu")
		(net "M_B_CPU0_SA_DQS_DP<2>")
	)
	(segment
		(start 296.850816 -293.869872)
		(end 296.835068 -293.869872)
		(width 0.16002)
		(layer "In2.Cu")
		(net "M_B_CPU0_SA_DQS_DP<2>")
	)
	(segment
		(start 311.195974 -286.37865)
		(end 310.642762 -286.37865)
		(width 0.18288)
		(layer "In2.Cu")
		(net "M_B_CPU0_SA_DQS_DP<2>")
	)
	(segment
		(start 334.973168 -265.80338)
		(end 334.97266 -265.803888)
		(width 0.088646)
		(layer "In2.Cu")
		(net "M_B_CPU0_SA_DQS_DP<2>")
	)
	(segment
		(start 304.925222 -291.92093)
		(end 304.717704 -292.128448)
		(width 0.18288)
		(layer "In2.Cu")
		(net "M_B_CPU0_SA_DQS_DP<2>")
	)
	(segment
		(start 331.626464 -266.034774)
		(end 330.622148 -267.03909)
		(width 0.088646)
		(layer "In2.Cu")
		(net "M_B_CPU0_SA_DQS_DP<2>")
	)
	(segment
		(start 312.034174 -285.54045)
		(end 311.195974 -286.37865)
		(width 0.18288)
		(layer "In2.Cu")
		(net "M_B_CPU0_SA_DQS_DP<2>")
	)
	(segment
		(start 297.050968 -294.085772)
		(end 297.050968 -294.070024)
		(width 0.16002)
		(layer "In2.Cu")
		(net "M_B_CPU0_SA_DQS_DP<2>")
	)
	(segment
		(start 312.306462 -285.268162)
		(end 312.278268 -285.296356)
		(width 0.16002)
		(layer "In2.Cu")
		(net "M_B_CPU0_SA_DQS_DP<2>")
	)
	(segment
		(start 309.787036 -287.234376)
		(end 309.382922 -287.63849)
		(width 0.18288)
		(layer "In2.Cu")
		(net "M_B_CPU0_SA_DQS_DP<2>")
	)
	(segment
		(start 313.887104 -284.68447)
		(end 313.601862 -284.969712)
		(width 0.18288)
		(layer "In2.Cu")
		(net "M_B_CPU0_SA_DQS_DP<2>")
	)
	(segment
		(start 306.312316 -291.497766)
		(end 306.284122 -291.52596)
		(width 0.16002)
		(layer "In2.Cu")
		(net "M_B_CPU0_SA_DQS_DP<2>")
	)
	(segment
		(start 300.126146 -294.551862)
		(end 299.941996 -294.367712)
		(width 0.18288)
		(layer "In2.Cu")
		(net "M_B_CPU0_SA_DQS_DP<2>")
	)
	(segment
		(start 314.159392 -284.412182)
		(end 314.131198 -284.440376)
		(width 0.16002)
		(layer "In2.Cu")
		(net "M_B_CPU0_SA_DQS_DP<2>")
	)
	(segment
		(start 314.463684 -284.10789)
		(end 314.159392 -284.412182)
		(width 0.18288)
		(layer "In2.Cu")
		(net "M_B_CPU0_SA_DQS_DP<2>")
	)
	(segment
		(start 300.604174 -295.02989)
		(end 300.398434 -294.82415)
		(width 0.18288)
		(layer "In2.Cu")
		(net "M_B_CPU0_SA_DQS_DP<2>")
	)
	(segment
		(start 307.026564 -290.783264)
		(end 306.55641 -291.253672)
		(width 0.18288)
		(layer "In2.Cu")
		(net "M_B_CPU0_SA_DQS_DP<2>")
	)
	(segment
		(start 299.258482 -294.641524)
		(end 298.777406 -294.641524)
		(width 0.18288)
		(layer "In2.Cu")
		(net "M_B_CPU0_SA_DQS_DP<2>")
	)
	(segment
		(start 300.398434 -294.82415)
		(end 300.37024 -294.795956)
		(width 0.16002)
		(layer "In2.Cu")
		(net "M_B_CPU0_SA_DQS_DP<2>")
	)
	(segment
		(start 296.653966 -293.68877)
		(end 296.262044 -293.68877)
		(width 0.18288)
		(layer "In2.Cu")
		(net "M_B_CPU0_SA_DQS_DP<2>")
	)
	(segment
		(start 333.093568 -265.80338)
		(end 333.09306 -265.803888)
		(width 0.088646)
		(layer "In2.Cu")
		(net "M_B_CPU0_SA_DQS_DP<2>")
	)
	(segment
		(start 304.445416 -292.400736)
		(end 303.011586 -293.834566)
		(width 0.18288)
		(layer "In2.Cu")
		(net "M_B_CPU0_SA_DQS_DP<2>")
	)
	(segment
		(start 314.11545 -284.440376)
		(end 313.915298 -284.640528)
		(width 0.16002)
		(layer "In2.Cu")
		(net "M_B_CPU0_SA_DQS_DP<2>")
	)
	(arc
		(start 334.598264 -265.803888)
		(mid 334.315562 -265.87963)
		(end 334.03286 -265.803888)
		(width 0.088646)
		(layer "In2.Cu")
		(net "M_B_CPU0_SA_DQS_DP<2>")
	)
	(arc
		(start 332.241652 -265.845544)
		(mid 332.134613 -265.822771)
		(end 332.025498 -265.831066)
		(width 0.088646)
		(layer "In2.Cu")
		(net "M_B_CPU0_SA_DQS_DP<2>")
	)
	(arc
		(start 332.025498 -265.831066)
		(mid 331.982793 -265.843482)
		(end 331.941932 -265.861038)
		(width 0.088646)
		(layer "In2.Cu")
		(net "M_B_CPU0_SA_DQS_DP<2>")
	)
	(arc
		(start 336.38236 -265.638534)
		(mid 336.282693 -265.678235)
		(end 336.175858 -265.688064)
		(width 0.088646)
		(layer "In2.Cu")
		(net "M_B_CPU0_SA_DQS_DP<2>")
	)
	(arc
		(start 335.537556 -265.80338)
		(mid 335.255362 -265.878936)
		(end 334.973168 -265.80338)
		(width 0.088646)
		(layer "In2.Cu")
		(net "M_B_CPU0_SA_DQS_DP<2>")
	)
	(arc
		(start 332.718664 -265.803888)
		(mid 332.484792 -265.877656)
		(end 332.241652 -265.845544)
		(width 0.088646)
		(layer "In2.Cu")
		(net "M_B_CPU0_SA_DQS_DP<2>")
	)
	(arc
		(start 336.476086 -265.595354)
		(mid 336.428233 -265.614795)
		(end 336.38236 -265.638534)
		(width 0.088646)
		(layer "In2.Cu")
		(net "M_B_CPU0_SA_DQS_DP<2>")
	)
	(arc
		(start 333.657956 -265.80338)
		(mid 333.375762 -265.878936)
		(end 333.093568 -265.80338)
		(width 0.088646)
		(layer "In2.Cu")
		(net "M_B_CPU0_SA_DQS_DP<2>")
	)
	(arc
		(start 331.698092 -265.982958)
		(mid 331.660175 -266.005962)
		(end 331.626464 -266.034774)
		(width 0.088646)
		(layer "In2.Cu")
		(net "M_B_CPU0_SA_DQS_DP<2>")
	)
	(arc
		(start 334.03286 -265.803888)
		(mid 333.845662 -265.753745)
		(end 333.658464 -265.803888)
		(width 0.088646)
		(layer "In2.Cu")
		(net "M_B_CPU0_SA_DQS_DP<2>")
	)
	(arc
		(start 333.09306 -265.803888)
		(mid 332.905862 -265.753745)
		(end 332.718664 -265.803888)
		(width 0.088646)
		(layer "In2.Cu")
		(net "M_B_CPU0_SA_DQS_DP<2>")
	)
	(arc
		(start 335.967578 -265.688064)
		(mid 335.744964 -265.717383)
		(end 335.537556 -265.80338)
		(width 0.088646)
		(layer "In2.Cu")
		(net "M_B_CPU0_SA_DQS_DP<2>")
	)
	(arc
		(start 334.97266 -265.803888)
		(mid 334.785462 -265.753745)
		(end 334.598264 -265.803888)
		(width 0.088646)
		(layer "In2.Cu")
		(net "M_B_CPU0_SA_DQS_DP<2>")
	)
	(segment
		(start 291.969952 -303.73066)
		(end 291.70884 -303.991772)
		(width 0.20066)
		(layer "F.Cu")
		(net "M_B_CPU0_SA_DQS_DP<1>")
	)
	(segment
		(start 293.250874 -303.566576)
		(end 292.989762 -303.305464)
		(width 0.20066)
		(layer "F.Cu")
		(net "M_B_CPU0_SA_DQS_DP<1>")
	)
	(segment
		(start 292.295834 -303.73066)
		(end 291.969952 -303.73066)
		(width 0.20066)
		(layer "F.Cu")
		(net "M_B_CPU0_SA_DQS_DP<1>")
	)
	(segment
		(start 291.233352 -303.991772)
		(end 289.477958 -303.991772)
		(width 0.1016)
		(layer "F.Cu")
		(net "M_B_CPU0_SA_DQS_DP<1>")
	)
	(segment
		(start 291.70884 -303.991772)
		(end 291.556694 -303.991772)
		(width 0.20066)
		(layer "F.Cu")
		(net "M_B_CPU0_SA_DQS_DP<1>")
	)
	(segment
		(start 340.424516 -272.639028)
		(end 340.424262 -272.639282)
		(width 0.20066)
		(layer "F.Cu")
		(net "M_B_CPU0_SA_DQS_DP<1>")
	)
	(segment
		(start 289.240976 -303.991772)
		(end 289.231578 -304.00117)
		(width 0.101854)
		(layer "F.Cu")
		(net "M_B_CPU0_SA_DQS_DP<1>")
	)
	(segment
		(start 288.742882 -303.73066)
		(end 288.115756 -303.73066)
		(width 0.20066)
		(layer "F.Cu")
		(net "M_B_CPU0_SA_DQS_DP<1>")
	)
	(segment
		(start 292.989762 -303.305464)
		(end 292.72103 -303.305464)
		(width 0.20066)
		(layer "F.Cu")
		(net "M_B_CPU0_SA_DQS_DP<1>")
	)
	(segment
		(start 294.904414 -303.566576)
		(end 293.799514 -303.566576)
		(width 0.20066)
		(layer "F.Cu")
		(net "M_B_CPU0_SA_DQS_DP<1>")
	)
	(segment
		(start 340.424516 -272.103342)
		(end 340.424516 -272.639028)
		(width 0.20066)
		(layer "F.Cu")
		(net "M_B_CPU0_SA_DQS_DP<1>")
	)
	(segment
		(start 289.013392 -304.00117)
		(end 288.742882 -303.73066)
		(width 0.20066)
		(layer "F.Cu")
		(net "M_B_CPU0_SA_DQS_DP<1>")
	)
	(segment
		(start 287.47974 -303.305464)
		(end 287.054798 -303.305464)
		(width 0.20066)
		(layer "F.Cu")
		(net "M_B_CPU0_SA_DQS_DP<1>")
	)
	(segment
		(start 288.115756 -303.73066)
		(end 287.47974 -303.305464)
		(width 0.20066)
		(layer "F.Cu")
		(net "M_B_CPU0_SA_DQS_DP<1>")
	)
	(segment
		(start 293.799514 -303.566576)
		(end 293.250874 -303.566576)
		(width 0.20066)
		(layer "F.Cu")
		(net "M_B_CPU0_SA_DQS_DP<1>")
	)
	(segment
		(start 289.231578 -304.00117)
		(end 289.013392 -304.00117)
		(width 0.20066)
		(layer "F.Cu")
		(net "M_B_CPU0_SA_DQS_DP<1>")
	)
	(segment
		(start 287.054798 -303.305464)
		(end 286.793686 -303.566576)
		(width 0.20066)
		(layer "F.Cu")
		(net "M_B_CPU0_SA_DQS_DP<1>")
	)
	(segment
		(start 286.793686 -303.566576)
		(end 286.255714 -303.566576)
		(width 0.20066)
		(layer "F.Cu")
		(net "M_B_CPU0_SA_DQS_DP<1>")
	)
	(segment
		(start 292.72103 -303.305464)
		(end 292.295834 -303.73066)
		(width 0.20066)
		(layer "F.Cu")
		(net "M_B_CPU0_SA_DQS_DP<1>")
	)
	(segment
		(start 289.477958 -303.991772)
		(end 289.240976 -303.991772)
		(width 0.101854)
		(layer "F.Cu")
		(net "M_B_CPU0_SA_DQS_DP<1>")
	)
	(segment
		(start 291.556694 -303.991772)
		(end 291.233352 -303.991772)
		(width 0.101854)
		(layer "F.Cu")
		(net "M_B_CPU0_SA_DQS_DP<1>")
	)
	(segment
		(start 313.036966 -299.454316)
		(end 312.15457 -300.336712)
		(width 0.18288)
		(layer "In4.Cu")
		(net "M_B_CPU0_SA_DQS_DP<1>")
	)
	(segment
		(start 295.185592 -303.285398)
		(end 294.904414 -303.566576)
		(width 0.18288)
		(layer "In4.Cu")
		(net "M_B_CPU0_SA_DQS_DP<1>")
	)
	(segment
		(start 313.633358 -299.454316)
		(end 313.036966 -299.454316)
		(width 0.18288)
		(layer "In4.Cu")
		(net "M_B_CPU0_SA_DQS_DP<1>")
	)
	(segment
		(start 331.180694 -278.396446)
		(end 325.029322 -284.536388)
		(width 0.18288)
		(layer "In4.Cu")
		(net "M_B_CPU0_SA_DQS_DP<1>")
	)
	(segment
		(start 331.318362 -278.258778)
		(end 331.283818 -278.293322)
		(width 0.088646)
		(layer "In4.Cu")
		(net "M_B_CPU0_SA_DQS_DP<1>")
	)
	(segment
		(start 314.56884 -299.438822)
		(end 314.26912 -299.738542)
		(width 0.18288)
		(layer "In4.Cu")
		(net "M_B_CPU0_SA_DQS_DP<1>")
	)
	(segment
		(start 334.130904 -274.754848)
		(end 334.12811 -274.756372)
		(width 0.088646)
		(layer "In4.Cu")
		(net "M_B_CPU0_SA_DQS_DP<1>")
	)
	(segment
		(start 307.546756 -301.325534)
		(end 305.787806 -303.084484)
		(width 0.18288)
		(layer "In4.Cu")
		(net "M_B_CPU0_SA_DQS_DP<1>")
	)
	(segment
		(start 333.25689 -276.296374)
		(end 333.059024 -276.49424)
		(width 0.088646)
		(layer "In4.Cu")
		(net "M_B_CPU0_SA_DQS_DP<1>")
	)
	(segment
		(start 309.499762 -300.297596)
		(end 309.083964 -300.297596)
		(width 0.18288)
		(layer "In4.Cu")
		(net "M_B_CPU0_SA_DQS_DP<1>")
	)
	(segment
		(start 331.318362 -278.173942)
		(end 331.318362 -278.258778)
		(width 0.088646)
		(layer "In4.Cu")
		(net "M_B_CPU0_SA_DQS_DP<1>")
	)
	(segment
		(start 310.43245 -300.336712)
		(end 310.17718 -300.591982)
		(width 0.18288)
		(layer "In4.Cu")
		(net "M_B_CPU0_SA_DQS_DP<1>")
	)
	(segment
		(start 325.029322 -284.536388)
		(end 321.580256 -292.91153)
		(width 0.18288)
		(layer "In4.Cu")
		(net "M_B_CPU0_SA_DQS_DP<1>")
	)
	(segment
		(start 321.580256 -292.91153)
		(end 315.052964 -299.438822)
		(width 0.18288)
		(layer "In4.Cu")
		(net "M_B_CPU0_SA_DQS_DP<1>")
	)
	(segment
		(start 333.059024 -276.97303)
		(end 332.003908 -278.028146)
		(width 0.088646)
		(layer "In4.Cu")
		(net "M_B_CPU0_SA_DQS_DP<1>")
	)
	(segment
		(start 309.794148 -300.591982)
		(end 309.499762 -300.297596)
		(width 0.18288)
		(layer "In4.Cu")
		(net "M_B_CPU0_SA_DQS_DP<1>")
	)
	(segment
		(start 331.283818 -278.293322)
		(end 331.180694 -278.396446)
		(width 0.18288)
		(layer "In4.Cu")
		(net "M_B_CPU0_SA_DQS_DP<1>")
	)
	(segment
		(start 299.451776 -303.723548)
		(end 299.183552 -303.991772)
		(width 0.18288)
		(layer "In4.Cu")
		(net "M_B_CPU0_SA_DQS_DP<1>")
	)
	(segment
		(start 296.001694 -303.034192)
		(end 295.750488 -303.285398)
		(width 0.18288)
		(layer "In4.Cu")
		(net "M_B_CPU0_SA_DQS_DP<1>")
	)
	(segment
		(start 312.15457 -300.336712)
		(end 310.43245 -300.336712)
		(width 0.18288)
		(layer "In4.Cu")
		(net "M_B_CPU0_SA_DQS_DP<1>")
	)
	(segment
		(start 333.059024 -276.49424)
		(end 333.059024 -276.97303)
		(width 0.088646)
		(layer "In4.Cu")
		(net "M_B_CPU0_SA_DQS_DP<1>")
	)
	(segment
		(start 334.60436 -273.939)
		(end 334.601058 -273.941032)
		(width 0.088646)
		(layer "In4.Cu")
		(net "M_B_CPU0_SA_DQS_DP<1>")
	)
	(segment
		(start 331.382116 -278.110442)
		(end 331.318362 -278.173942)
		(width 0.088646)
		(layer "In4.Cu")
		(net "M_B_CPU0_SA_DQS_DP<1>")
	)
	(segment
		(start 333.940658 -275.08073)
		(end 333.940658 -275.099272)
		(width 0.088646)
		(layer "In4.Cu")
		(net "M_B_CPU0_SA_DQS_DP<1>")
	)
	(segment
		(start 339.397086 -273.005804)
		(end 339.39226 -273.008344)
		(width 0.088646)
		(layer "In4.Cu")
		(net "M_B_CPU0_SA_DQS_DP<1>")
	)
	(segment
		(start 305.787806 -303.084484)
		(end 304.146204 -303.084484)
		(width 0.18288)
		(layer "In4.Cu")
		(net "M_B_CPU0_SA_DQS_DP<1>")
	)
	(segment
		(start 334.134206 -274.752816)
		(end 334.130904 -274.754848)
		(width 0.088646)
		(layer "In4.Cu")
		(net "M_B_CPU0_SA_DQS_DP<1>")
	)
	(segment
		(start 334.126586 -274.757134)
		(end 334.11922 -274.761452)
		(width 0.088646)
		(layer "In4.Cu")
		(net "M_B_CPU0_SA_DQS_DP<1>")
	)
	(segment
		(start 315.052964 -299.438822)
		(end 314.56884 -299.438822)
		(width 0.18288)
		(layer "In4.Cu")
		(net "M_B_CPU0_SA_DQS_DP<1>")
	)
	(segment
		(start 304.146204 -303.084484)
		(end 302.603154 -303.723548)
		(width 0.18288)
		(layer "In4.Cu")
		(net "M_B_CPU0_SA_DQS_DP<1>")
	)
	(segment
		(start 334.598264 -273.942556)
		(end 334.59674 -273.943318)
		(width 0.088646)
		(layer "In4.Cu")
		(net "M_B_CPU0_SA_DQS_DP<1>")
	)
	(segment
		(start 332.003908 -278.028146)
		(end 331.464412 -278.028146)
		(width 0.088646)
		(layer "In4.Cu")
		(net "M_B_CPU0_SA_DQS_DP<1>")
	)
	(segment
		(start 314.26912 -299.738542)
		(end 313.917584 -299.738542)
		(width 0.18288)
		(layer "In4.Cu")
		(net "M_B_CPU0_SA_DQS_DP<1>")
	)
	(segment
		(start 339.03666 -273.008344)
		(end 338.81314 -273.137122)
		(width 0.088646)
		(layer "In4.Cu")
		(net "M_B_CPU0_SA_DQS_DP<1>")
	)
	(segment
		(start 298.536868 -303.715166)
		(end 298.034964 -303.715166)
		(width 0.18288)
		(layer "In4.Cu")
		(net "M_B_CPU0_SA_DQS_DP<1>")
	)
	(segment
		(start 299.183552 -303.991772)
		(end 298.813474 -303.991772)
		(width 0.18288)
		(layer "In4.Cu")
		(net "M_B_CPU0_SA_DQS_DP<1>")
	)
	(segment
		(start 298.034964 -303.715166)
		(end 297.35399 -303.034192)
		(width 0.18288)
		(layer "In4.Cu")
		(net "M_B_CPU0_SA_DQS_DP<1>")
	)
	(segment
		(start 297.35399 -303.034192)
		(end 296.001694 -303.034192)
		(width 0.18288)
		(layer "In4.Cu")
		(net "M_B_CPU0_SA_DQS_DP<1>")
	)
	(segment
		(start 331.464412 -278.028146)
		(end 331.382116 -278.110442)
		(width 0.088646)
		(layer "In4.Cu")
		(net "M_B_CPU0_SA_DQS_DP<1>")
	)
	(segment
		(start 302.603154 -303.723548)
		(end 299.451776 -303.723548)
		(width 0.18288)
		(layer "In4.Cu")
		(net "M_B_CPU0_SA_DQS_DP<1>")
	)
	(segment
		(start 298.813474 -303.991772)
		(end 298.536868 -303.715166)
		(width 0.18288)
		(layer "In4.Cu")
		(net "M_B_CPU0_SA_DQS_DP<1>")
	)
	(segment
		(start 313.917584 -299.738542)
		(end 313.633358 -299.454316)
		(width 0.18288)
		(layer "In4.Cu")
		(net "M_B_CPU0_SA_DQS_DP<1>")
	)
	(segment
		(start 295.750488 -303.285398)
		(end 295.185592 -303.285398)
		(width 0.18288)
		(layer "In4.Cu")
		(net "M_B_CPU0_SA_DQS_DP<1>")
	)
	(segment
		(start 334.59674 -273.943318)
		(end 334.589374 -273.947636)
		(width 0.088646)
		(layer "In4.Cu")
		(net "M_B_CPU0_SA_DQS_DP<1>")
	)
	(segment
		(start 340.083902 -272.729198)
		(end 339.658706 -272.971006)
		(width 0.088646)
		(layer "In4.Cu")
		(net "M_B_CPU0_SA_DQS_DP<1>")
	)
	(segment
		(start 334.601058 -273.941032)
		(end 334.598264 -273.942556)
		(width 0.088646)
		(layer "In4.Cu")
		(net "M_B_CPU0_SA_DQS_DP<1>")
	)
	(segment
		(start 333.657448 -275.57095)
		(end 333.64932 -275.575522)
		(width 0.088646)
		(layer "In4.Cu")
		(net "M_B_CPU0_SA_DQS_DP<1>")
	)
	(segment
		(start 334.12811 -274.756372)
		(end 334.126586 -274.757134)
		(width 0.088646)
		(layer "In4.Cu")
		(net "M_B_CPU0_SA_DQS_DP<1>")
	)
	(segment
		(start 333.65821 -275.570442)
		(end 333.657448 -275.57095)
		(width 0.088646)
		(layer "In4.Cu")
		(net "M_B_CPU0_SA_DQS_DP<1>")
	)
	(segment
		(start 336.947764 -273.12874)
		(end 336.933032 -273.137376)
		(width 0.088646)
		(layer "In4.Cu")
		(net "M_B_CPU0_SA_DQS_DP<1>")
	)
	(segment
		(start 310.17718 -300.591982)
		(end 309.794148 -300.591982)
		(width 0.18288)
		(layer "In4.Cu")
		(net "M_B_CPU0_SA_DQS_DP<1>")
	)
	(segment
		(start 334.880966 -273.444462)
		(end 334.880966 -273.453098)
		(width 0.088646)
		(layer "In4.Cu")
		(net "M_B_CPU0_SA_DQS_DP<1>")
	)
	(segment
		(start 339.454236 -273.012662)
		(end 339.397086 -273.005804)
		(width 0.088646)
		(layer "In4.Cu")
		(net "M_B_CPU0_SA_DQS_DP<1>")
	)
	(segment
		(start 309.083964 -300.297596)
		(end 307.546756 -301.325534)
		(width 0.18288)
		(layer "In4.Cu")
		(net "M_B_CPU0_SA_DQS_DP<1>")
	)
	(segment
		(start 339.39226 -273.008344)
		(end 339.03666 -273.008344)
		(width 0.088646)
		(layer "In4.Cu")
		(net "M_B_CPU0_SA_DQS_DP<1>")
	)
	(arc
		(start 335.068164 -273.12874)
		(mid 334.933231 -273.262094)
		(end 334.880966 -273.444462)
		(width 0.088646)
		(layer "In4.Cu")
		(net "M_B_CPU0_SA_DQS_DP<1>")
	)
	(arc
		(start 334.880966 -273.453098)
		(mid 334.806975 -273.732664)
		(end 334.60436 -273.939)
		(width 0.088646)
		(layer "In4.Cu")
		(net "M_B_CPU0_SA_DQS_DP<1>")
	)
	(arc
		(start 333.47279 -275.85035)
		(mid 333.402414 -276.091545)
		(end 333.25689 -276.296374)
		(width 0.088646)
		(layer "In4.Cu")
		(net "M_B_CPU0_SA_DQS_DP<1>")
	)
	(arc
		(start 336.007964 -273.12874)
		(mid 335.725262 -273.204516)
		(end 335.44256 -273.12874)
		(width 0.088646)
		(layer "In4.Cu")
		(net "M_B_CPU0_SA_DQS_DP<1>")
	)
	(arc
		(start 339.658706 -272.971006)
		(mid 339.559864 -273.008516)
		(end 339.454236 -273.012662)
		(width 0.088646)
		(layer "In4.Cu")
		(net "M_B_CPU0_SA_DQS_DP<1>")
	)
	(arc
		(start 337.887564 -273.12874)
		(mid 337.604862 -273.204516)
		(end 337.32216 -273.12874)
		(width 0.088646)
		(layer "In4.Cu")
		(net "M_B_CPU0_SA_DQS_DP<1>")
	)
	(arc
		(start 334.589374 -273.947636)
		(mid 334.45846 -274.083996)
		(end 334.410812 -274.266914)
		(width 0.088646)
		(layer "In4.Cu")
		(net "M_B_CPU0_SA_DQS_DP<1>")
	)
	(arc
		(start 335.44256 -273.12874)
		(mid 335.255362 -273.078597)
		(end 335.068164 -273.12874)
		(width 0.088646)
		(layer "In4.Cu")
		(net "M_B_CPU0_SA_DQS_DP<1>")
	)
	(arc
		(start 337.32216 -273.12874)
		(mid 337.134962 -273.078597)
		(end 336.947764 -273.12874)
		(width 0.088646)
		(layer "In4.Cu")
		(net "M_B_CPU0_SA_DQS_DP<1>")
	)
	(arc
		(start 338.81314 -273.137122)
		(mid 338.536475 -273.204593)
		(end 338.26196 -273.12874)
		(width 0.088646)
		(layer "In4.Cu")
		(net "M_B_CPU0_SA_DQS_DP<1>")
	)
	(arc
		(start 340.424262 -272.639282)
		(mid 340.248241 -272.662119)
		(end 340.083902 -272.729198)
		(width 0.088646)
		(layer "In4.Cu")
		(net "M_B_CPU0_SA_DQS_DP<1>")
	)
	(arc
		(start 336.38236 -273.12874)
		(mid 336.195162 -273.078597)
		(end 336.007964 -273.12874)
		(width 0.088646)
		(layer "In4.Cu")
		(net "M_B_CPU0_SA_DQS_DP<1>")
	)
	(arc
		(start 333.64932 -275.575522)
		(mid 333.529602 -275.692722)
		(end 333.47279 -275.85035)
		(width 0.088646)
		(layer "In4.Cu")
		(net "M_B_CPU0_SA_DQS_DP<1>")
	)
	(arc
		(start 334.410812 -274.266914)
		(mid 334.336821 -274.54648)
		(end 334.134206 -274.752816)
		(width 0.088646)
		(layer "In4.Cu")
		(net "M_B_CPU0_SA_DQS_DP<1>")
	)
	(arc
		(start 334.11922 -274.761452)
		(mid 333.988306 -274.897812)
		(end 333.940658 -275.08073)
		(width 0.088646)
		(layer "In4.Cu")
		(net "M_B_CPU0_SA_DQS_DP<1>")
	)
	(arc
		(start 338.26196 -273.12874)
		(mid 338.074762 -273.078597)
		(end 337.887564 -273.12874)
		(width 0.088646)
		(layer "In4.Cu")
		(net "M_B_CPU0_SA_DQS_DP<1>")
	)
	(arc
		(start 336.933032 -273.137376)
		(mid 336.656557 -273.204696)
		(end 336.38236 -273.12874)
		(width 0.088646)
		(layer "In4.Cu")
		(net "M_B_CPU0_SA_DQS_DP<1>")
	)
	(arc
		(start 333.940658 -275.099272)
		(mid 333.860496 -275.371461)
		(end 333.65821 -275.570442)
		(width 0.088646)
		(layer "In4.Cu")
		(net "M_B_CPU0_SA_DQS_DP<1>")
	)
	(segment
		(start 289.240976 -313.341766)
		(end 289.231578 -313.351164)
		(width 0.101854)
		(layer "F.Cu")
		(net "M_B_CPU0_SA_DQS_DP<0>")
	)
	(segment
		(start 288.115756 -313.080654)
		(end 287.47974 -312.655458)
		(width 0.20066)
		(layer "F.Cu")
		(net "M_B_CPU0_SA_DQS_DP<0>")
	)
	(segment
		(start 292.989762 -312.655458)
		(end 292.72103 -312.655458)
		(width 0.20066)
		(layer "F.Cu")
		(net "M_B_CPU0_SA_DQS_DP<0>")
	)
	(segment
		(start 289.477958 -313.341766)
		(end 289.240976 -313.341766)
		(width 0.101854)
		(layer "F.Cu")
		(net "M_B_CPU0_SA_DQS_DP<0>")
	)
	(segment
		(start 287.47974 -312.655458)
		(end 287.054798 -312.655458)
		(width 0.20066)
		(layer "F.Cu")
		(net "M_B_CPU0_SA_DQS_DP<0>")
	)
	(segment
		(start 292.295834 -313.080654)
		(end 291.969952 -313.080654)
		(width 0.20066)
		(layer "F.Cu")
		(net "M_B_CPU0_SA_DQS_DP<0>")
	)
	(segment
		(start 287.054798 -312.655458)
		(end 286.793686 -312.91657)
		(width 0.20066)
		(layer "F.Cu")
		(net "M_B_CPU0_SA_DQS_DP<0>")
	)
	(segment
		(start 291.70884 -313.341766)
		(end 291.556694 -313.341766)
		(width 0.20066)
		(layer "F.Cu")
		(net "M_B_CPU0_SA_DQS_DP<0>")
	)
	(segment
		(start 291.969952 -313.080654)
		(end 291.70884 -313.341766)
		(width 0.20066)
		(layer "F.Cu")
		(net "M_B_CPU0_SA_DQS_DP<0>")
	)
	(segment
		(start 289.013392 -313.351164)
		(end 288.742882 -313.080654)
		(width 0.20066)
		(layer "F.Cu")
		(net "M_B_CPU0_SA_DQS_DP<0>")
	)
	(segment
		(start 337.134962 -274.54479)
		(end 337.134962 -275.08073)
		(width 0.20066)
		(layer "F.Cu")
		(net "M_B_CPU0_SA_DQS_DP<0>")
	)
	(segment
		(start 293.250874 -312.91657)
		(end 292.989762 -312.655458)
		(width 0.20066)
		(layer "F.Cu")
		(net "M_B_CPU0_SA_DQS_DP<0>")
	)
	(segment
		(start 292.72103 -312.655458)
		(end 292.295834 -313.080654)
		(width 0.20066)
		(layer "F.Cu")
		(net "M_B_CPU0_SA_DQS_DP<0>")
	)
	(segment
		(start 288.742882 -313.080654)
		(end 288.115756 -313.080654)
		(width 0.20066)
		(layer "F.Cu")
		(net "M_B_CPU0_SA_DQS_DP<0>")
	)
	(segment
		(start 293.799514 -312.91657)
		(end 293.250874 -312.91657)
		(width 0.20066)
		(layer "F.Cu")
		(net "M_B_CPU0_SA_DQS_DP<0>")
	)
	(segment
		(start 291.233352 -313.341766)
		(end 289.477958 -313.341766)
		(width 0.1016)
		(layer "F.Cu")
		(net "M_B_CPU0_SA_DQS_DP<0>")
	)
	(segment
		(start 294.904414 -312.91657)
		(end 293.799514 -312.91657)
		(width 0.20066)
		(layer "F.Cu")
		(net "M_B_CPU0_SA_DQS_DP<0>")
	)
	(segment
		(start 289.231578 -313.351164)
		(end 289.013392 -313.351164)
		(width 0.20066)
		(layer "F.Cu")
		(net "M_B_CPU0_SA_DQS_DP<0>")
	)
	(segment
		(start 286.793686 -312.91657)
		(end 286.255714 -312.91657)
		(width 0.20066)
		(layer "F.Cu")
		(net "M_B_CPU0_SA_DQS_DP<0>")
	)
	(segment
		(start 291.556694 -313.341766)
		(end 291.233352 -313.341766)
		(width 0.101854)
		(layer "F.Cu")
		(net "M_B_CPU0_SA_DQS_DP<0>")
	)
	(segment
		(start 336.88782 -275.327872)
		(end 336.517996 -275.327872)
		(width 0.088646)
		(layer "In2.Cu")
		(net "M_B_CPU0_SA_DQS_DP<0>")
	)
	(segment
		(start 300.588172 -313.72429)
		(end 300.390814 -313.526932)
		(width 0.18288)
		(layer "In2.Cu")
		(net "M_B_CPU0_SA_DQS_DP<0>")
	)
	(segment
		(start 313.54522 -313.07151)
		(end 312.114946 -313.07151)
		(width 0.18288)
		(layer "In2.Cu")
		(net "M_B_CPU0_SA_DQS_DP<0>")
	)
	(segment
		(start 304.462688 -314.333128)
		(end 304.262536 -314.132976)
		(width 0.16002)
		(layer "In2.Cu")
		(net "M_B_CPU0_SA_DQS_DP<0>")
	)
	(segment
		(start 336.517996 -275.327872)
		(end 336.369406 -275.412454)
		(width 0.088646)
		(layer "In2.Cu")
		(net "M_B_CPU0_SA_DQS_DP<0>")
	)
	(segment
		(start 334.517238 -279.648666)
		(end 334.514952 -279.64638)
		(width 0.088646)
		(layer "In2.Cu")
		(net "M_B_CPU0_SA_DQS_DP<0>")
	)
	(segment
		(start 297.365166 -313.099958)
		(end 297.079162 -312.813954)
		(width 0.18288)
		(layer "In2.Cu")
		(net "M_B_CPU0_SA_DQS_DP<0>")
	)
	(segment
		(start 307.854096 -314.110878)
		(end 307.500528 -314.110878)
		(width 0.18288)
		(layer "In2.Cu")
		(net "M_B_CPU0_SA_DQS_DP<0>")
	)
	(segment
		(start 310.295036 -313.07151)
		(end 310.007762 -313.358784)
		(width 0.18288)
		(layer "In2.Cu")
		(net "M_B_CPU0_SA_DQS_DP<0>")
	)
	(segment
		(start 297.079162 -312.813954)
		(end 297.050968 -312.78576)
		(width 0.16002)
		(layer "In2.Cu")
		(net "M_B_CPU0_SA_DQS_DP<0>")
	)
	(segment
		(start 331.256386 -284.494986)
		(end 330.625196 -286.019748)
		(width 0.18288)
		(layer "In2.Cu")
		(net "M_B_CPU0_SA_DQS_DP<0>")
	)
	(segment
		(start 297.050968 -312.78576)
		(end 297.050968 -312.770012)
		(width 0.16002)
		(layer "In2.Cu")
		(net "M_B_CPU0_SA_DQS_DP<0>")
	)
	(segment
		(start 333.377286 -280.08834)
		(end 331.464666 -282.00096)
		(width 0.18288)
		(layer "In2.Cu")
		(net "M_B_CPU0_SA_DQS_DP<0>")
	)
	(segment
		(start 300.14672 -313.282838)
		(end 300.118526 -313.254644)
		(width 0.16002)
		(layer "In2.Cu")
		(net "M_B_CPU0_SA_DQS_DP<0>")
	)
	(segment
		(start 336.107786 -275.447252)
		(end 336.10296 -275.449792)
		(width 0.088646)
		(layer "In2.Cu")
		(net "M_B_CPU0_SA_DQS_DP<0>")
	)
	(segment
		(start 306.424076 -314.333128)
		(end 306.424076 -314.348876)
		(width 0.16002)
		(layer "In2.Cu")
		(net "M_B_CPU0_SA_DQS_DP<0>")
	)
	(segment
		(start 302.098456 -313.72429)
		(end 300.588172 -313.72429)
		(width 0.18288)
		(layer "In2.Cu")
		(net "M_B_CPU0_SA_DQS_DP<0>")
	)
	(segment
		(start 334.514952 -279.64638)
		(end 334.478376 -279.625298)
		(width 0.088646)
		(layer "In2.Cu")
		(net "M_B_CPU0_SA_DQS_DP<0>")
	)
	(segment
		(start 307.500528 -314.110878)
		(end 307.228748 -313.839098)
		(width 0.18288)
		(layer "In2.Cu")
		(net "M_B_CPU0_SA_DQS_DP<0>")
	)
	(segment
		(start 302.295814 -313.526932)
		(end 302.098456 -313.72429)
		(width 0.18288)
		(layer "In2.Cu")
		(net "M_B_CPU0_SA_DQS_DP<0>")
	)
	(segment
		(start 314.25388 -312.36285)
		(end 314.10783 -312.5089)
		(width 0.18288)
		(layer "In2.Cu")
		(net "M_B_CPU0_SA_DQS_DP<0>")
	)
	(segment
		(start 335.638648 -275.511514)
		(end 335.529428 -275.57476)
		(width 0.088646)
		(layer "In2.Cu")
		(net "M_B_CPU0_SA_DQS_DP<0>")
	)
	(segment
		(start 333.377286 -280.003504)
		(end 333.377286 -280.08834)
		(width 0.088646)
		(layer "In2.Cu")
		(net "M_B_CPU0_SA_DQS_DP<0>")
	)
	(segment
		(start 306.424076 -314.348876)
		(end 306.395882 -314.37707)
		(width 0.16002)
		(layer "In2.Cu")
		(net "M_B_CPU0_SA_DQS_DP<0>")
	)
	(segment
		(start 304.218594 -314.104782)
		(end 303.228502 -313.11469)
		(width 0.18288)
		(layer "In2.Cu")
		(net "M_B_CPU0_SA_DQS_DP<0>")
	)
	(segment
		(start 315.8109 -311.715404)
		(end 314.25388 -312.36285)
		(width 0.18288)
		(layer "In2.Cu")
		(net "M_B_CPU0_SA_DQS_DP<0>")
	)
	(segment
		(start 302.568102 -313.254644)
		(end 302.539908 -313.282838)
		(width 0.16002)
		(layer "In2.Cu")
		(net "M_B_CPU0_SA_DQS_DP<0>")
	)
	(segment
		(start 335.548478 -278.819864)
		(end 335.537556 -278.826214)
		(width 0.088646)
		(layer "In2.Cu")
		(net "M_B_CPU0_SA_DQS_DP<0>")
	)
	(segment
		(start 314.10783 -312.5089)
		(end 314.079636 -312.537094)
		(width 0.16002)
		(layer "In2.Cu")
		(net "M_B_CPU0_SA_DQS_DP<0>")
	)
	(segment
		(start 335.350358 -275.8948)
		(end 335.350612 -275.893784)
		(width 0.088646)
		(layer "In2.Cu")
		(net "M_B_CPU0_SA_DQS_DP<0>")
	)
	(segment
		(start 303.228502 -313.11469)
		(end 302.708056 -313.11469)
		(width 0.18288)
		(layer "In2.Cu")
		(net "M_B_CPU0_SA_DQS_DP<0>")
	)
	(segment
		(start 304.262536 -314.132976)
		(end 304.246788 -314.132976)
		(width 0.16002)
		(layer "In2.Cu")
		(net "M_B_CPU0_SA_DQS_DP<0>")
	)
	(segment
		(start 295.152572 -312.668412)
		(end 294.904414 -312.91657)
		(width 0.18288)
		(layer "In2.Cu")
		(net "M_B_CPU0_SA_DQS_DP<0>")
	)
	(segment
		(start 304.68824 -314.574428)
		(end 304.490882 -314.37707)
		(width 0.18288)
		(layer "In2.Cu")
		(net "M_B_CPU0_SA_DQS_DP<0>")
	)
	(segment
		(start 302.324008 -313.48299)
		(end 302.324008 -313.498738)
		(width 0.16002)
		(layer "In2.Cu")
		(net "M_B_CPU0_SA_DQS_DP<0>")
	)
	(segment
		(start 330.625196 -286.019748)
		(end 328.081132 -288.564066)
		(width 0.18288)
		(layer "In2.Cu")
		(net "M_B_CPU0_SA_DQS_DP<0>")
	)
	(segment
		(start 310.007762 -313.358784)
		(end 309.979568 -313.386978)
		(width 0.16002)
		(layer "In2.Cu")
		(net "M_B_CPU0_SA_DQS_DP<0>")
	)
	(segment
		(start 309.763668 -313.58713)
		(end 309.763668 -313.602878)
		(width 0.16002)
		(layer "In2.Cu")
		(net "M_B_CPU0_SA_DQS_DP<0>")
	)
	(segment
		(start 307.228748 -313.839098)
		(end 306.933854 -313.839098)
		(width 0.18288)
		(layer "In2.Cu")
		(net "M_B_CPU0_SA_DQS_DP<0>")
	)
	(segment
		(start 300.162468 -313.282838)
		(end 300.14672 -313.282838)
		(width 0.16002)
		(layer "In2.Cu")
		(net "M_B_CPU0_SA_DQS_DP<0>")
	)
	(segment
		(start 302.708056 -313.11469)
		(end 302.568102 -313.254644)
		(width 0.18288)
		(layer "In2.Cu")
		(net "M_B_CPU0_SA_DQS_DP<0>")
	)
	(segment
		(start 322.7451 -302.962818)
		(end 321.459606 -306.066952)
		(width 0.18288)
		(layer "In2.Cu")
		(net "M_B_CPU0_SA_DQS_DP<0>")
	)
	(segment
		(start 335.54924 -276.225762)
		(end 335.54924 -276.226016)
		(width 0.088646)
		(layer "In2.Cu")
		(net "M_B_CPU0_SA_DQS_DP<0>")
	)
	(segment
		(start 298.794678 -313.342528)
		(end 298.552108 -313.099958)
		(width 0.18288)
		(layer "In2.Cu")
		(net "M_B_CPU0_SA_DQS_DP<0>")
	)
	(segment
		(start 304.462688 -314.348876)
		(end 304.462688 -314.333128)
		(width 0.16002)
		(layer "In2.Cu")
		(net "M_B_CPU0_SA_DQS_DP<0>")
	)
	(segment
		(start 304.490882 -314.37707)
		(end 304.462688 -314.348876)
		(width 0.16002)
		(layer "In2.Cu")
		(net "M_B_CPU0_SA_DQS_DP<0>")
	)
	(segment
		(start 306.933854 -313.839098)
		(end 306.66817 -314.104782)
		(width 0.18288)
		(layer "In2.Cu")
		(net "M_B_CPU0_SA_DQS_DP<0>")
	)
	(segment
		(start 309.96382 -313.386978)
		(end 309.763668 -313.58713)
		(width 0.16002)
		(layer "In2.Cu")
		(net "M_B_CPU0_SA_DQS_DP<0>")
	)
	(segment
		(start 336.007202 -278.012398)
		(end 335.998312 -278.017478)
		(width 0.088646)
		(layer "In2.Cu")
		(net "M_B_CPU0_SA_DQS_DP<0>")
	)
	(segment
		(start 335.074006 -279.636474)
		(end 335.07299 -279.636982)
		(width 0.088646)
		(layer "In2.Cu")
		(net "M_B_CPU0_SA_DQS_DP<0>")
	)
	(segment
		(start 311.489598 -313.34329)
		(end 311.217818 -313.07151)
		(width 0.18288)
		(layer "In2.Cu")
		(net "M_B_CPU0_SA_DQS_DP<0>")
	)
	(segment
		(start 296.835068 -312.56986)
		(end 296.806874 -312.541666)
		(width 0.16002)
		(layer "In2.Cu")
		(net "M_B_CPU0_SA_DQS_DP<0>")
	)
	(segment
		(start 306.395882 -314.37707)
		(end 306.198524 -314.574428)
		(width 0.18288)
		(layer "In2.Cu")
		(net "M_B_CPU0_SA_DQS_DP<0>")
	)
	(segment
		(start 334.126332 -279.625806)
		(end 334.126332 -279.625552)
		(width 0.088646)
		(layer "In2.Cu")
		(net "M_B_CPU0_SA_DQS_DP<0>")
	)
	(segment
		(start 335.538064 -276.219158)
		(end 335.543906 -276.222714)
		(width 0.088646)
		(layer "In2.Cu")
		(net "M_B_CPU0_SA_DQS_DP<0>")
	)
	(segment
		(start 302.52416 -313.282838)
		(end 302.324008 -313.48299)
		(width 0.16002)
		(layer "In2.Cu")
		(net "M_B_CPU0_SA_DQS_DP<0>")
	)
	(segment
		(start 335.820258 -276.708616)
		(end 335.820512 -276.708616)
		(width 0.088646)
		(layer "In2.Cu")
		(net "M_B_CPU0_SA_DQS_DP<0>")
	)
	(segment
		(start 300.118526 -313.254644)
		(end 299.891958 -313.028076)
		(width 0.18288)
		(layer "In2.Cu")
		(net "M_B_CPU0_SA_DQS_DP<0>")
	)
	(segment
		(start 337.134962 -275.08073)
		(end 336.88782 -275.327872)
		(width 0.088646)
		(layer "In2.Cu")
		(net "M_B_CPU0_SA_DQS_DP<0>")
	)
	(segment
		(start 296.658538 -312.39333)
		(end 296.138346 -312.39333)
		(width 0.18288)
		(layer "In2.Cu")
		(net "M_B_CPU0_SA_DQS_DP<0>")
	)
	(segment
		(start 311.843166 -313.34329)
		(end 311.489598 -313.34329)
		(width 0.18288)
		(layer "In2.Cu")
		(net "M_B_CPU0_SA_DQS_DP<0>")
	)
	(segment
		(start 302.324008 -313.498738)
		(end 302.295814 -313.526932)
		(width 0.16002)
		(layer "In2.Cu")
		(net "M_B_CPU0_SA_DQS_DP<0>")
	)
	(segment
		(start 335.820512 -276.708616)
		(end 335.820512 -276.720554)
		(width 0.088646)
		(layer "In2.Cu")
		(net "M_B_CPU0_SA_DQS_DP<0>")
	)
	(segment
		(start 314.063888 -312.537094)
		(end 313.863736 -312.737246)
		(width 0.16002)
		(layer "In2.Cu")
		(net "M_B_CPU0_SA_DQS_DP<0>")
	)
	(segment
		(start 333.977996 -279.767792)
		(end 333.612998 -279.767792)
		(width 0.088646)
		(layer "In2.Cu")
		(net "M_B_CPU0_SA_DQS_DP<0>")
	)
	(segment
		(start 334.114902 -279.634442)
		(end 334.113886 -279.635204)
		(width 0.088646)
		(layer "In2.Cu")
		(net "M_B_CPU0_SA_DQS_DP<0>")
	)
	(segment
		(start 306.198524 -314.574428)
		(end 304.68824 -314.574428)
		(width 0.18288)
		(layer "In2.Cu")
		(net "M_B_CPU0_SA_DQS_DP<0>")
	)
	(segment
		(start 313.835542 -312.781188)
		(end 313.54522 -313.07151)
		(width 0.18288)
		(layer "In2.Cu")
		(net "M_B_CPU0_SA_DQS_DP<0>")
	)
	(segment
		(start 335.07299 -279.636982)
		(end 335.072228 -279.63749)
		(width 0.088646)
		(layer "In2.Cu")
		(net "M_B_CPU0_SA_DQS_DP<0>")
	)
	(segment
		(start 335.869026 -275.449792)
		(end 335.638648 -275.511514)
		(width 0.088646)
		(layer "In2.Cu")
		(net "M_B_CPU0_SA_DQS_DP<0>")
	)
	(segment
		(start 296.138346 -312.39333)
		(end 295.474136 -312.668412)
		(width 0.18288)
		(layer "In2.Cu")
		(net "M_B_CPU0_SA_DQS_DP<0>")
	)
	(segment
		(start 295.474136 -312.668412)
		(end 295.152572 -312.668412)
		(width 0.18288)
		(layer "In2.Cu")
		(net "M_B_CPU0_SA_DQS_DP<0>")
	)
	(segment
		(start 297.050968 -312.770012)
		(end 296.850816 -312.56986)
		(width 0.16002)
		(layer "In2.Cu")
		(net "M_B_CPU0_SA_DQS_DP<0>")
	)
	(segment
		(start 335.529174 -276.214078)
		(end 335.538064 -276.219158)
		(width 0.088646)
		(layer "In2.Cu")
		(net "M_B_CPU0_SA_DQS_DP<0>")
	)
	(segment
		(start 335.069942 -279.63876)
		(end 335.06791 -279.64003)
		(width 0.088646)
		(layer "In2.Cu")
		(net "M_B_CPU0_SA_DQS_DP<0>")
	)
	(segment
		(start 308.125876 -313.839098)
		(end 307.854096 -314.110878)
		(width 0.18288)
		(layer "In2.Cu")
		(net "M_B_CPU0_SA_DQS_DP<0>")
	)
	(segment
		(start 309.735474 -313.631072)
		(end 309.527448 -313.839098)
		(width 0.18288)
		(layer "In2.Cu")
		(net "M_B_CPU0_SA_DQS_DP<0>")
	)
	(segment
		(start 328.081132 -288.564066)
		(end 323.325998 -300.041818)
		(width 0.18288)
		(layer "In2.Cu")
		(net "M_B_CPU0_SA_DQS_DP<0>")
	)
	(segment
		(start 296.806874 -312.541666)
		(end 296.658538 -312.39333)
		(width 0.18288)
		(layer "In2.Cu")
		(net "M_B_CPU0_SA_DQS_DP<0>")
	)
	(segment
		(start 300.36262 -313.48299)
		(end 300.162468 -313.282838)
		(width 0.16002)
		(layer "In2.Cu")
		(net "M_B_CPU0_SA_DQS_DP<0>")
	)
	(segment
		(start 312.114946 -313.07151)
		(end 311.843166 -313.34329)
		(width 0.18288)
		(layer "In2.Cu")
		(net "M_B_CPU0_SA_DQS_DP<0>")
	)
	(segment
		(start 306.639976 -314.132976)
		(end 306.624228 -314.132976)
		(width 0.16002)
		(layer "In2.Cu")
		(net "M_B_CPU0_SA_DQS_DP<0>")
	)
	(segment
		(start 296.850816 -312.56986)
		(end 296.835068 -312.56986)
		(width 0.16002)
		(layer "In2.Cu")
		(net "M_B_CPU0_SA_DQS_DP<0>")
	)
	(segment
		(start 299.496734 -313.028076)
		(end 299.182282 -313.342528)
		(width 0.18288)
		(layer "In2.Cu")
		(net "M_B_CPU0_SA_DQS_DP<0>")
	)
	(segment
		(start 334.113886 -279.635204)
		(end 333.977996 -279.767792)
		(width 0.088646)
		(layer "In2.Cu")
		(net "M_B_CPU0_SA_DQS_DP<0>")
	)
	(segment
		(start 323.325998 -300.041818)
		(end 322.7451 -302.962818)
		(width 0.18288)
		(layer "In2.Cu")
		(net "M_B_CPU0_SA_DQS_DP<0>")
	)
	(segment
		(start 321.459606 -306.066952)
		(end 315.8109 -311.715404)
		(width 0.18288)
		(layer "In2.Cu")
		(net "M_B_CPU0_SA_DQS_DP<0>")
	)
	(segment
		(start 309.763668 -313.602878)
		(end 309.735474 -313.631072)
		(width 0.16002)
		(layer "In2.Cu")
		(net "M_B_CPU0_SA_DQS_DP<0>")
	)
	(segment
		(start 302.539908 -313.282838)
		(end 302.52416 -313.282838)
		(width 0.16002)
		(layer "In2.Cu")
		(net "M_B_CPU0_SA_DQS_DP<0>")
	)
	(segment
		(start 313.863736 -312.737246)
		(end 313.863736 -312.752994)
		(width 0.16002)
		(layer "In2.Cu")
		(net "M_B_CPU0_SA_DQS_DP<0>")
	)
	(segment
		(start 311.217818 -313.07151)
		(end 310.295036 -313.07151)
		(width 0.18288)
		(layer "In2.Cu")
		(net "M_B_CPU0_SA_DQS_DP<0>")
	)
	(segment
		(start 335.537556 -278.826214)
		(end 335.526126 -278.832818)
		(width 0.088646)
		(layer "In2.Cu")
		(net "M_B_CPU0_SA_DQS_DP<0>")
	)
	(segment
		(start 336.289904 -277.508462)
		(end 336.290158 -277.522686)
		(width 0.088646)
		(layer "In2.Cu")
		(net "M_B_CPU0_SA_DQS_DP<0>")
	)
	(segment
		(start 309.979568 -313.386978)
		(end 309.96382 -313.386978)
		(width 0.16002)
		(layer "In2.Cu")
		(net "M_B_CPU0_SA_DQS_DP<0>")
	)
	(segment
		(start 333.612998 -279.767792)
		(end 333.377286 -280.003504)
		(width 0.088646)
		(layer "In2.Cu")
		(net "M_B_CPU0_SA_DQS_DP<0>")
	)
	(segment
		(start 331.464666 -283.991812)
		(end 331.256386 -284.494986)
		(width 0.18288)
		(layer "In2.Cu")
		(net "M_B_CPU0_SA_DQS_DP<0>")
	)
	(segment
		(start 335.070958 -279.638252)
		(end 335.069942 -279.63876)
		(width 0.088646)
		(layer "In2.Cu")
		(net "M_B_CPU0_SA_DQS_DP<0>")
	)
	(segment
		(start 313.863736 -312.752994)
		(end 313.835542 -312.781188)
		(width 0.16002)
		(layer "In2.Cu")
		(net "M_B_CPU0_SA_DQS_DP<0>")
	)
	(segment
		(start 300.36262 -313.498738)
		(end 300.36262 -313.48299)
		(width 0.16002)
		(layer "In2.Cu")
		(net "M_B_CPU0_SA_DQS_DP<0>")
	)
	(segment
		(start 299.891958 -313.028076)
		(end 299.496734 -313.028076)
		(width 0.18288)
		(layer "In2.Cu")
		(net "M_B_CPU0_SA_DQS_DP<0>")
	)
	(segment
		(start 335.072228 -279.63749)
		(end 335.070958 -279.638252)
		(width 0.088646)
		(layer "In2.Cu")
		(net "M_B_CPU0_SA_DQS_DP<0>")
	)
	(segment
		(start 314.079636 -312.537094)
		(end 314.063888 -312.537094)
		(width 0.16002)
		(layer "In2.Cu")
		(net "M_B_CPU0_SA_DQS_DP<0>")
	)
	(segment
		(start 335.529428 -275.57476)
		(end 335.52892 -275.575522)
		(width 0.088646)
		(layer "In2.Cu")
		(net "M_B_CPU0_SA_DQS_DP<0>")
	)
	(segment
		(start 298.552108 -313.099958)
		(end 297.365166 -313.099958)
		(width 0.18288)
		(layer "In2.Cu")
		(net "M_B_CPU0_SA_DQS_DP<0>")
	)
	(segment
		(start 304.246788 -314.132976)
		(end 304.218594 -314.104782)
		(width 0.16002)
		(layer "In2.Cu")
		(net "M_B_CPU0_SA_DQS_DP<0>")
	)
	(segment
		(start 306.66817 -314.104782)
		(end 306.639976 -314.132976)
		(width 0.16002)
		(layer "In2.Cu")
		(net "M_B_CPU0_SA_DQS_DP<0>")
	)
	(segment
		(start 336.023204 -278.003)
		(end 336.007202 -278.012398)
		(width 0.088646)
		(layer "In2.Cu")
		(net "M_B_CPU0_SA_DQS_DP<0>")
	)
	(segment
		(start 306.624228 -314.132976)
		(end 306.424076 -314.333128)
		(width 0.16002)
		(layer "In2.Cu")
		(net "M_B_CPU0_SA_DQS_DP<0>")
	)
	(segment
		(start 300.390814 -313.526932)
		(end 300.36262 -313.498738)
		(width 0.16002)
		(layer "In2.Cu")
		(net "M_B_CPU0_SA_DQS_DP<0>")
	)
	(segment
		(start 336.10296 -275.449792)
		(end 335.869026 -275.449792)
		(width 0.088646)
		(layer "In2.Cu")
		(net "M_B_CPU0_SA_DQS_DP<0>")
	)
	(segment
		(start 331.464666 -282.00096)
		(end 331.464666 -283.991812)
		(width 0.18288)
		(layer "In2.Cu")
		(net "M_B_CPU0_SA_DQS_DP<0>")
	)
	(segment
		(start 309.527448 -313.839098)
		(end 308.125876 -313.839098)
		(width 0.18288)
		(layer "In2.Cu")
		(net "M_B_CPU0_SA_DQS_DP<0>")
	)
	(segment
		(start 336.164936 -275.45411)
		(end 336.107786 -275.447252)
		(width 0.088646)
		(layer "In2.Cu")
		(net "M_B_CPU0_SA_DQS_DP<0>")
	)
	(segment
		(start 299.182282 -313.342528)
		(end 298.794678 -313.342528)
		(width 0.18288)
		(layer "In2.Cu")
		(net "M_B_CPU0_SA_DQS_DP<0>")
	)
	(arc
		(start 335.526126 -278.832818)
		(mid 335.397235 -278.968866)
		(end 335.350358 -279.150318)
		(width 0.088646)
		(layer "In2.Cu")
		(net "M_B_CPU0_SA_DQS_DP<0>")
	)
	(arc
		(start 335.54924 -276.226016)
		(mid 335.747881 -276.431865)
		(end 335.820258 -276.708616)
		(width 0.088646)
		(layer "In2.Cu")
		(net "M_B_CPU0_SA_DQS_DP<0>")
	)
	(arc
		(start 336.369406 -275.412454)
		(mid 336.270564 -275.449964)
		(end 336.164936 -275.45411)
		(width 0.088646)
		(layer "In2.Cu")
		(net "M_B_CPU0_SA_DQS_DP<0>")
	)
	(arc
		(start 336.290158 -277.522686)
		(mid 336.218921 -277.797423)
		(end 336.023204 -278.003)
		(width 0.088646)
		(layer "In2.Cu")
		(net "M_B_CPU0_SA_DQS_DP<0>")
	)
	(arc
		(start 335.52892 -275.575522)
		(mid 335.398006 -275.711882)
		(end 335.350358 -275.8948)
		(width 0.088646)
		(layer "In2.Cu")
		(net "M_B_CPU0_SA_DQS_DP<0>")
	)
	(arc
		(start 335.998312 -278.017478)
		(mid 335.867398 -278.153838)
		(end 335.81975 -278.336756)
		(width 0.088646)
		(layer "In2.Cu")
		(net "M_B_CPU0_SA_DQS_DP<0>")
	)
	(arc
		(start 334.126332 -279.625552)
		(mid 334.120323 -279.629619)
		(end 334.114902 -279.634442)
		(width 0.088646)
		(layer "In2.Cu")
		(net "M_B_CPU0_SA_DQS_DP<0>")
	)
	(arc
		(start 335.820512 -276.720554)
		(mid 335.873559 -276.901168)
		(end 336.00771 -277.033228)
		(width 0.088646)
		(layer "In2.Cu")
		(net "M_B_CPU0_SA_DQS_DP<0>")
	)
	(arc
		(start 336.00771 -277.033228)
		(mid 336.21077 -277.234037)
		(end 336.289904 -277.508462)
		(width 0.088646)
		(layer "In2.Cu")
		(net "M_B_CPU0_SA_DQS_DP<0>")
	)
	(arc
		(start 335.543906 -276.222714)
		(mid 335.546577 -276.224231)
		(end 335.54924 -276.225762)
		(width 0.088646)
		(layer "In2.Cu")
		(net "M_B_CPU0_SA_DQS_DP<0>")
	)
	(arc
		(start 335.81975 -278.336756)
		(mid 335.747354 -278.613823)
		(end 335.548478 -278.819864)
		(width 0.088646)
		(layer "In2.Cu")
		(net "M_B_CPU0_SA_DQS_DP<0>")
	)
	(arc
		(start 335.06791 -279.64003)
		(mid 334.793711 -279.715865)
		(end 334.517238 -279.648666)
		(width 0.088646)
		(layer "In2.Cu")
		(net "M_B_CPU0_SA_DQS_DP<0>")
	)
	(arc
		(start 335.350612 -275.893784)
		(mid 335.350612 -275.894292)
		(end 335.350612 -275.8948)
		(width 0.088646)
		(layer "In2.Cu")
		(net "M_B_CPU0_SA_DQS_DP<0>")
	)
	(arc
		(start 334.478376 -279.625298)
		(mid 334.302295 -279.578411)
		(end 334.126332 -279.625806)
		(width 0.088646)
		(layer "In2.Cu")
		(net "M_B_CPU0_SA_DQS_DP<0>")
	)
	(arc
		(start 335.350358 -279.150318)
		(mid 335.276505 -279.429964)
		(end 335.074006 -279.636474)
		(width 0.088646)
		(layer "In2.Cu")
		(net "M_B_CPU0_SA_DQS_DP<0>")
	)
	(arc
		(start 335.350612 -275.8948)
		(mid 335.398291 -276.0777)
		(end 335.529174 -276.214078)
		(width 0.088646)
		(layer "In2.Cu")
		(net "M_B_CPU0_SA_DQS_DP<0>")
	)
	(segment
		(start 296.444416 -274.405598)
		(end 297.147996 -274.405598)
		(width 0.20066)
		(layer "F.Cu")
		(net "M_B_CPU0_SA_DQS_DN<9>")
	)
	(segment
		(start 291.984176 -273.983196)
		(end 292.223952 -273.983196)
		(width 0.20066)
		(layer "F.Cu")
		(net "M_B_CPU0_SA_DQS_DN<9>")
	)
	(segment
		(start 292.223952 -273.983196)
		(end 292.492176 -274.25142)
		(width 0.20066)
		(layer "F.Cu")
		(net "M_B_CPU0_SA_DQS_DN<9>")
	)
	(segment
		(start 292.67531 -274.25142)
		(end 292.684962 -274.241768)
		(width 0.101854)
		(layer "F.Cu")
		(net "M_B_CPU0_SA_DQS_DN<9>")
	)
	(segment
		(start 295.403778 -273.980656)
		(end 295.8084 -273.980656)
		(width 0.20066)
		(layer "F.Cu")
		(net "M_B_CPU0_SA_DQS_DN<9>")
	)
	(segment
		(start 297.409108 -274.66671)
		(end 297.899582 -274.66671)
		(width 0.20066)
		(layer "F.Cu")
		(net "M_B_CPU0_SA_DQS_DN<9>")
	)
	(segment
		(start 295.8084 -273.980656)
		(end 296.444416 -274.405598)
		(width 0.20066)
		(layer "F.Cu")
		(net "M_B_CPU0_SA_DQS_DN<9>")
	)
	(segment
		(start 299.029882 -274.666964)
		(end 299.029628 -274.66671)
		(width 0.20066)
		(layer "F.Cu")
		(net "M_B_CPU0_SA_DQS_DN<9>")
	)
	(segment
		(start 295.000426 -274.241768)
		(end 295.142666 -274.241768)
		(width 0.20066)
		(layer "F.Cu")
		(net "M_B_CPU0_SA_DQS_DN<9>")
	)
	(segment
		(start 299.029628 -274.66671)
		(end 297.899582 -274.66671)
		(width 0.20066)
		(layer "F.Cu")
		(net "M_B_CPU0_SA_DQS_DN<9>")
	)
	(segment
		(start 291.088572 -274.405598)
		(end 291.561774 -274.405598)
		(width 0.20066)
		(layer "F.Cu")
		(net "M_B_CPU0_SA_DQS_DN<9>")
	)
	(segment
		(start 292.684962 -274.241768)
		(end 292.92296 -274.241768)
		(width 0.101854)
		(layer "F.Cu")
		(net "M_B_CPU0_SA_DQS_DN<9>")
	)
	(segment
		(start 295.142666 -274.241768)
		(end 295.403778 -273.980656)
		(width 0.20066)
		(layer "F.Cu")
		(net "M_B_CPU0_SA_DQS_DN<9>")
	)
	(segment
		(start 338.074762 -260.430518)
		(end 338.075016 -260.430772)
		(width 0.20066)
		(layer "F.Cu")
		(net "M_B_CPU0_SA_DQS_DN<9>")
	)
	(segment
		(start 292.492176 -274.25142)
		(end 292.67531 -274.25142)
		(width 0.20066)
		(layer "F.Cu")
		(net "M_B_CPU0_SA_DQS_DN<9>")
	)
	(segment
		(start 290.82746 -274.66671)
		(end 291.088572 -274.405598)
		(width 0.20066)
		(layer "F.Cu")
		(net "M_B_CPU0_SA_DQS_DN<9>")
	)
	(segment
		(start 292.92296 -274.241768)
		(end 295.000426 -274.241768)
		(width 0.1016)
		(layer "F.Cu")
		(net "M_B_CPU0_SA_DQS_DN<9>")
	)
	(segment
		(start 290.355782 -274.66671)
		(end 290.82746 -274.66671)
		(width 0.20066)
		(layer "F.Cu")
		(net "M_B_CPU0_SA_DQS_DN<9>")
	)
	(segment
		(start 291.561774 -274.405598)
		(end 291.984176 -273.983196)
		(width 0.20066)
		(layer "F.Cu")
		(net "M_B_CPU0_SA_DQS_DN<9>")
	)
	(segment
		(start 338.074762 -259.894832)
		(end 338.074762 -260.430518)
		(width 0.20066)
		(layer "F.Cu")
		(net "M_B_CPU0_SA_DQS_DN<9>")
	)
	(segment
		(start 297.147996 -274.405598)
		(end 297.409108 -274.66671)
		(width 0.20066)
		(layer "F.Cu")
		(net "M_B_CPU0_SA_DQS_DN<9>")
	)
	(segment
		(start 304.673254 -273.4564)
		(end 304.47361 -273.656044)
		(width 0.16002)
		(layer "In2.Cu")
		(net "M_B_CPU0_SA_DQS_DN<9>")
	)
	(segment
		(start 302.34128 -274.550632)
		(end 302.313086 -274.522438)
		(width 0.16002)
		(layer "In2.Cu")
		(net "M_B_CPU0_SA_DQS_DN<9>")
	)
	(segment
		(start 331.769212 -260.182106)
		(end 329.727306 -262.224012)
		(width 0.088646)
		(layer "In2.Cu")
		(net "M_B_CPU0_SA_DQS_DN<9>")
	)
	(segment
		(start 337.337146 -260.11505)
		(end 337.322414 -260.106414)
		(width 0.088646)
		(layer "In2.Cu")
		(net "M_B_CPU0_SA_DQS_DN<9>")
	)
	(segment
		(start 313.985148 -272.000726)
		(end 313.956954 -271.972532)
		(width 0.16002)
		(layer "In2.Cu")
		(net "M_B_CPU0_SA_DQS_DN<9>")
	)
	(segment
		(start 313.956954 -271.956276)
		(end 313.75731 -271.756632)
		(width 0.16002)
		(layer "In2.Cu")
		(net "M_B_CPU0_SA_DQS_DN<9>")
	)
	(segment
		(start 302.528478 -274.73783)
		(end 302.34128 -274.550632)
		(width 0.18288)
		(layer "In2.Cu")
		(net "M_B_CPU0_SA_DQS_DN<9>")
	)
	(segment
		(start 311.989216 -272.000726)
		(end 311.215532 -272.77441)
		(width 0.18288)
		(layer "In2.Cu")
		(net "M_B_CPU0_SA_DQS_DN<9>")
	)
	(segment
		(start 312.217054 -271.756632)
		(end 312.01741 -271.956276)
		(width 0.16002)
		(layer "In2.Cu")
		(net "M_B_CPU0_SA_DQS_DN<9>")
	)
	(segment
		(start 338.271104 -260.111494)
		(end 338.263738 -260.107176)
		(width 0.088646)
		(layer "In2.Cu")
		(net "M_B_CPU0_SA_DQS_DN<9>")
	)
	(segment
		(start 328.986134 -262.343646)
		(end 328.962766 -262.343646)
		(width 0.088646)
		(layer "In2.Cu")
		(net "M_B_CPU0_SA_DQS_DN<9>")
	)
	(segment
		(start 306.712366 -273.971512)
		(end 306.441348 -273.700494)
		(width 0.18288)
		(layer "In2.Cu")
		(net "M_B_CPU0_SA_DQS_DN<9>")
	)
	(segment
		(start 331.966062 -260.182106)
		(end 331.769212 -260.182106)
		(width 0.088646)
		(layer "In2.Cu")
		(net "M_B_CPU0_SA_DQS_DN<9>")
	)
	(segment
		(start 306.076604 -273.33575)
		(end 304.81016 -273.33575)
		(width 0.18288)
		(layer "In2.Cu")
		(net "M_B_CPU0_SA_DQS_DN<9>")
	)
	(segment
		(start 300.70933 -274.18665)
		(end 300.617636 -274.278344)
		(width 0.18288)
		(layer "In2.Cu")
		(net "M_B_CPU0_SA_DQS_DN<9>")
	)
	(segment
		(start 309.940198 -273.450304)
		(end 309.740046 -273.650456)
		(width 0.16002)
		(layer "In2.Cu")
		(net "M_B_CPU0_SA_DQS_DN<9>")
	)
	(segment
		(start 313.71286 -271.728438)
		(end 313.620404 -271.635982)
		(width 0.18288)
		(layer "In2.Cu")
		(net "M_B_CPU0_SA_DQS_DN<9>")
	)
	(segment
		(start 309.955946 -273.450304)
		(end 309.940198 -273.450304)
		(width 0.16002)
		(layer "In2.Cu")
		(net "M_B_CPU0_SA_DQS_DN<9>")
	)
	(segment
		(start 314.77966 -272.19529)
		(end 314.179712 -272.19529)
		(width 0.18288)
		(layer "In2.Cu")
		(net "M_B_CPU0_SA_DQS_DN<9>")
	)
	(segment
		(start 304.81016 -273.33575)
		(end 304.717704 -273.428206)
		(width 0.18288)
		(layer "In2.Cu")
		(net "M_B_CPU0_SA_DQS_DN<9>")
	)
	(segment
		(start 306.16906 -273.428206)
		(end 306.076604 -273.33575)
		(width 0.18288)
		(layer "In2.Cu")
		(net "M_B_CPU0_SA_DQS_DN<9>")
	)
	(segment
		(start 304.47361 -273.6723)
		(end 304.445416 -273.700494)
		(width 0.16002)
		(layer "In2.Cu")
		(net "M_B_CPU0_SA_DQS_DN<9>")
	)
	(segment
		(start 328.962766 -262.343646)
		(end 326.478138 -262.343646)
		(width 0.18288)
		(layer "In2.Cu")
		(net "M_B_CPU0_SA_DQS_DN<9>")
	)
	(segment
		(start 302.068992 -274.278344)
		(end 301.977298 -274.18665)
		(width 0.18288)
		(layer "In2.Cu")
		(net "M_B_CPU0_SA_DQS_DN<9>")
	)
	(segment
		(start 329.727306 -262.224012)
		(end 329.105768 -262.224012)
		(width 0.088646)
		(layer "In2.Cu")
		(net "M_B_CPU0_SA_DQS_DN<9>")
	)
	(segment
		(start 303.06264 -274.73783)
		(end 302.528478 -274.73783)
		(width 0.18288)
		(layer "In2.Cu")
		(net "M_B_CPU0_SA_DQS_DN<9>")
	)
	(segment
		(start 304.717704 -273.428206)
		(end 304.68951 -273.4564)
		(width 0.16002)
		(layer "In2.Cu")
		(net "M_B_CPU0_SA_DQS_DN<9>")
	)
	(segment
		(start 338.075016 -260.430772)
		(end 338.387944 -260.430772)
		(width 0.088646)
		(layer "In2.Cu")
		(net "M_B_CPU0_SA_DQS_DN<9>")
	)
	(segment
		(start 299.372274 -274.307046)
		(end 299.187108 -274.307046)
		(width 0.18288)
		(layer "In2.Cu")
		(net "M_B_CPU0_SA_DQS_DN<9>")
	)
	(segment
		(start 301.977298 -274.18665)
		(end 300.70933 -274.18665)
		(width 0.18288)
		(layer "In2.Cu")
		(net "M_B_CPU0_SA_DQS_DN<9>")
	)
	(segment
		(start 300.373542 -274.522438)
		(end 300.345348 -274.550632)
		(width 0.16002)
		(layer "In2.Cu")
		(net "M_B_CPU0_SA_DQS_DN<9>")
	)
	(segment
		(start 307.38953 -274.243292)
		(end 307.11775 -273.971512)
		(width 0.18288)
		(layer "In2.Cu")
		(net "M_B_CPU0_SA_DQS_DN<9>")
	)
	(segment
		(start 307.11775 -273.971512)
		(end 306.712366 -273.971512)
		(width 0.18288)
		(layer "In2.Cu")
		(net "M_B_CPU0_SA_DQS_DN<9>")
	)
	(segment
		(start 302.097186 -274.306538)
		(end 302.068992 -274.278344)
		(width 0.16002)
		(layer "In2.Cu")
		(net "M_B_CPU0_SA_DQS_DN<9>")
	)
	(segment
		(start 302.313086 -274.506182)
		(end 302.113442 -274.306538)
		(width 0.16002)
		(layer "In2.Cu")
		(net "M_B_CPU0_SA_DQS_DN<9>")
	)
	(segment
		(start 300.573186 -274.306538)
		(end 300.373542 -274.506182)
		(width 0.16002)
		(layer "In2.Cu")
		(net "M_B_CPU0_SA_DQS_DN<9>")
	)
	(segment
		(start 300.21911 -274.67687)
		(end 299.742098 -274.67687)
		(width 0.18288)
		(layer "In2.Cu")
		(net "M_B_CPU0_SA_DQS_DN<9>")
	)
	(segment
		(start 300.373542 -274.506182)
		(end 300.373542 -274.522438)
		(width 0.16002)
		(layer "In2.Cu")
		(net "M_B_CPU0_SA_DQS_DN<9>")
	)
	(segment
		(start 336.392774 -260.11251)
		(end 336.38236 -260.106414)
		(width 0.088646)
		(layer "In2.Cu")
		(net "M_B_CPU0_SA_DQS_DN<9>")
	)
	(segment
		(start 307.743098 -274.243292)
		(end 307.38953 -274.243292)
		(width 0.18288)
		(layer "In2.Cu")
		(net "M_B_CPU0_SA_DQS_DN<9>")
	)
	(segment
		(start 306.441348 -273.700494)
		(end 306.413154 -273.6723)
		(width 0.16002)
		(layer "In2.Cu")
		(net "M_B_CPU0_SA_DQS_DN<9>")
	)
	(segment
		(start 302.313086 -274.522438)
		(end 302.313086 -274.506182)
		(width 0.16002)
		(layer "In2.Cu")
		(net "M_B_CPU0_SA_DQS_DN<9>")
	)
	(segment
		(start 310.63184 -272.77441)
		(end 309.98414 -273.42211)
		(width 0.18288)
		(layer "In2.Cu")
		(net "M_B_CPU0_SA_DQS_DN<9>")
	)
	(segment
		(start 304.445416 -273.700494)
		(end 303.959006 -274.186904)
		(width 0.18288)
		(layer "In2.Cu")
		(net "M_B_CPU0_SA_DQS_DN<9>")
	)
	(segment
		(start 306.21351 -273.4564)
		(end 306.197254 -273.4564)
		(width 0.16002)
		(layer "In2.Cu")
		(net "M_B_CPU0_SA_DQS_DN<9>")
	)
	(segment
		(start 306.413154 -273.656044)
		(end 306.21351 -273.4564)
		(width 0.16002)
		(layer "In2.Cu")
		(net "M_B_CPU0_SA_DQS_DN<9>")
	)
	(segment
		(start 299.187108 -274.307046)
		(end 299.08119 -274.412964)
		(width 0.18288)
		(layer "In2.Cu")
		(net "M_B_CPU0_SA_DQS_DN<9>")
	)
	(segment
		(start 325.206106 -263.615678)
		(end 322.051172 -264.926826)
		(width 0.18288)
		(layer "In2.Cu")
		(net "M_B_CPU0_SA_DQS_DN<9>")
	)
	(segment
		(start 306.413154 -273.6723)
		(end 306.413154 -273.656044)
		(width 0.16002)
		(layer "In2.Cu")
		(net "M_B_CPU0_SA_DQS_DN<9>")
	)
	(segment
		(start 304.68951 -273.4564)
		(end 304.673254 -273.4564)
		(width 0.16002)
		(layer "In2.Cu")
		(net "M_B_CPU0_SA_DQS_DN<9>")
	)
	(segment
		(start 300.589442 -274.306538)
		(end 300.573186 -274.306538)
		(width 0.16002)
		(layer "In2.Cu")
		(net "M_B_CPU0_SA_DQS_DN<9>")
	)
	(segment
		(start 306.197254 -273.4564)
		(end 306.16906 -273.428206)
		(width 0.16002)
		(layer "In2.Cu")
		(net "M_B_CPU0_SA_DQS_DN<9>")
	)
	(segment
		(start 300.617636 -274.278344)
		(end 300.589442 -274.306538)
		(width 0.16002)
		(layer "In2.Cu")
		(net "M_B_CPU0_SA_DQS_DN<9>")
	)
	(segment
		(start 338.263738 -260.107176)
		(end 338.262214 -260.106414)
		(width 0.088646)
		(layer "In2.Cu")
		(net "M_B_CPU0_SA_DQS_DN<9>")
	)
	(segment
		(start 303.959006 -274.186904)
		(end 303.613566 -274.186904)
		(width 0.18288)
		(layer "In2.Cu")
		(net "M_B_CPU0_SA_DQS_DN<9>")
	)
	(segment
		(start 312.261504 -271.728438)
		(end 312.23331 -271.756632)
		(width 0.16002)
		(layer "In2.Cu")
		(net "M_B_CPU0_SA_DQS_DN<9>")
	)
	(segment
		(start 309.740046 -273.666204)
		(end 309.711852 -273.694398)
		(width 0.16002)
		(layer "In2.Cu")
		(net "M_B_CPU0_SA_DQS_DN<9>")
	)
	(segment
		(start 326.478138 -262.343646)
		(end 325.206106 -263.615678)
		(width 0.18288)
		(layer "In2.Cu")
		(net "M_B_CPU0_SA_DQS_DN<9>")
	)
	(segment
		(start 313.741054 -271.756632)
		(end 313.71286 -271.728438)
		(width 0.16002)
		(layer "In2.Cu")
		(net "M_B_CPU0_SA_DQS_DN<9>")
	)
	(segment
		(start 308.014878 -273.971512)
		(end 307.743098 -274.243292)
		(width 0.18288)
		(layer "In2.Cu")
		(net "M_B_CPU0_SA_DQS_DN<9>")
	)
	(segment
		(start 311.215532 -272.77441)
		(end 310.63184 -272.77441)
		(width 0.18288)
		(layer "In2.Cu")
		(net "M_B_CPU0_SA_DQS_DN<9>")
	)
	(segment
		(start 299.742098 -274.67687)
		(end 299.372274 -274.307046)
		(width 0.18288)
		(layer "In2.Cu")
		(net "M_B_CPU0_SA_DQS_DN<9>")
	)
	(segment
		(start 303.613566 -274.186904)
		(end 303.06264 -274.73783)
		(width 0.18288)
		(layer "In2.Cu")
		(net "M_B_CPU0_SA_DQS_DN<9>")
	)
	(segment
		(start 300.345348 -274.550632)
		(end 300.21911 -274.67687)
		(width 0.18288)
		(layer "In2.Cu")
		(net "M_B_CPU0_SA_DQS_DN<9>")
	)
	(segment
		(start 314.179712 -272.19529)
		(end 313.985148 -272.000726)
		(width 0.18288)
		(layer "In2.Cu")
		(net "M_B_CPU0_SA_DQS_DN<9>")
	)
	(segment
		(start 313.75731 -271.756632)
		(end 313.741054 -271.756632)
		(width 0.16002)
		(layer "In2.Cu")
		(net "M_B_CPU0_SA_DQS_DN<9>")
	)
	(segment
		(start 299.029882 -274.536916)
		(end 299.029882 -274.666964)
		(width 0.18288)
		(layer "In2.Cu")
		(net "M_B_CPU0_SA_DQS_DN<9>")
	)
	(segment
		(start 299.08119 -274.412964)
		(end 299.029882 -274.536916)
		(width 0.18288)
		(layer "In2.Cu")
		(net "M_B_CPU0_SA_DQS_DN<9>")
	)
	(segment
		(start 322.051172 -264.926826)
		(end 314.77966 -272.19529)
		(width 0.18288)
		(layer "In2.Cu")
		(net "M_B_CPU0_SA_DQS_DN<9>")
	)
	(segment
		(start 312.01741 -271.956276)
		(end 312.01741 -271.972532)
		(width 0.16002)
		(layer "In2.Cu")
		(net "M_B_CPU0_SA_DQS_DN<9>")
	)
	(segment
		(start 309.98414 -273.42211)
		(end 309.955946 -273.450304)
		(width 0.16002)
		(layer "In2.Cu")
		(net "M_B_CPU0_SA_DQS_DN<9>")
	)
	(segment
		(start 309.434738 -273.971512)
		(end 308.014878 -273.971512)
		(width 0.18288)
		(layer "In2.Cu")
		(net "M_B_CPU0_SA_DQS_DN<9>")
	)
	(segment
		(start 309.740046 -273.650456)
		(end 309.740046 -273.666204)
		(width 0.16002)
		(layer "In2.Cu")
		(net "M_B_CPU0_SA_DQS_DN<9>")
	)
	(segment
		(start 313.956954 -271.972532)
		(end 313.956954 -271.956276)
		(width 0.16002)
		(layer "In2.Cu")
		(net "M_B_CPU0_SA_DQS_DN<9>")
	)
	(segment
		(start 313.620404 -271.635982)
		(end 312.35396 -271.635982)
		(width 0.18288)
		(layer "In2.Cu")
		(net "M_B_CPU0_SA_DQS_DN<9>")
	)
	(segment
		(start 312.23331 -271.756632)
		(end 312.217054 -271.756632)
		(width 0.16002)
		(layer "In2.Cu")
		(net "M_B_CPU0_SA_DQS_DN<9>")
	)
	(segment
		(start 312.01741 -271.972532)
		(end 311.989216 -272.000726)
		(width 0.16002)
		(layer "In2.Cu")
		(net "M_B_CPU0_SA_DQS_DN<9>")
	)
	(segment
		(start 338.387944 -260.430772)
		(end 338.445094 -260.373622)
		(width 0.088646)
		(layer "In2.Cu")
		(net "M_B_CPU0_SA_DQS_DN<9>")
	)
	(segment
		(start 312.35396 -271.635982)
		(end 312.261504 -271.728438)
		(width 0.18288)
		(layer "In2.Cu")
		(net "M_B_CPU0_SA_DQS_DN<9>")
	)
	(segment
		(start 304.47361 -273.656044)
		(end 304.47361 -273.6723)
		(width 0.16002)
		(layer "In2.Cu")
		(net "M_B_CPU0_SA_DQS_DN<9>")
	)
	(segment
		(start 329.105768 -262.224012)
		(end 328.986134 -262.343646)
		(width 0.088646)
		(layer "In2.Cu")
		(net "M_B_CPU0_SA_DQS_DN<9>")
	)
	(segment
		(start 302.113442 -274.306538)
		(end 302.097186 -274.306538)
		(width 0.16002)
		(layer "In2.Cu")
		(net "M_B_CPU0_SA_DQS_DN<9>")
	)
	(segment
		(start 309.711852 -273.694398)
		(end 309.434738 -273.971512)
		(width 0.18288)
		(layer "In2.Cu")
		(net "M_B_CPU0_SA_DQS_DN<9>")
	)
	(arc
		(start 336.948018 -260.106414)
		(mid 336.671205 -260.182284)
		(end 336.392774 -260.11251)
		(width 0.088646)
		(layer "In2.Cu")
		(net "M_B_CPU0_SA_DQS_DN<9>")
	)
	(arc
		(start 332.62316 -260.106414)
		(mid 332.435962 -260.056271)
		(end 332.248764 -260.106414)
		(width 0.088646)
		(layer "In2.Cu")
		(net "M_B_CPU0_SA_DQS_DN<9>")
	)
	(arc
		(start 335.44256 -260.106414)
		(mid 335.255362 -260.056271)
		(end 335.068164 -260.106414)
		(width 0.088646)
		(layer "In2.Cu")
		(net "M_B_CPU0_SA_DQS_DN<9>")
	)
	(arc
		(start 333.188564 -260.106414)
		(mid 332.905862 -260.18219)
		(end 332.62316 -260.106414)
		(width 0.088646)
		(layer "In2.Cu")
		(net "M_B_CPU0_SA_DQS_DN<9>")
	)
	(arc
		(start 333.56296 -260.106414)
		(mid 333.375762 -260.056271)
		(end 333.188564 -260.106414)
		(width 0.088646)
		(layer "In2.Cu")
		(net "M_B_CPU0_SA_DQS_DN<9>")
	)
	(arc
		(start 332.248764 -260.106414)
		(mid 332.112398 -260.162892)
		(end 331.966062 -260.182106)
		(width 0.088646)
		(layer "In2.Cu")
		(net "M_B_CPU0_SA_DQS_DN<9>")
	)
	(arc
		(start 334.128364 -260.106414)
		(mid 333.845662 -260.18219)
		(end 333.56296 -260.106414)
		(width 0.088646)
		(layer "In2.Cu")
		(net "M_B_CPU0_SA_DQS_DN<9>")
	)
	(arc
		(start 334.50276 -260.106414)
		(mid 334.315562 -260.056271)
		(end 334.128364 -260.106414)
		(width 0.088646)
		(layer "In2.Cu")
		(net "M_B_CPU0_SA_DQS_DN<9>")
	)
	(arc
		(start 338.262214 -260.106414)
		(mid 338.075016 -260.056271)
		(end 337.887818 -260.106414)
		(width 0.088646)
		(layer "In2.Cu")
		(net "M_B_CPU0_SA_DQS_DN<9>")
	)
	(arc
		(start 337.887818 -260.106414)
		(mid 337.613619 -260.182249)
		(end 337.337146 -260.11505)
		(width 0.088646)
		(layer "In2.Cu")
		(net "M_B_CPU0_SA_DQS_DN<9>")
	)
	(arc
		(start 337.322414 -260.106414)
		(mid 337.135216 -260.056271)
		(end 336.948018 -260.106414)
		(width 0.088646)
		(layer "In2.Cu")
		(net "M_B_CPU0_SA_DQS_DN<9>")
	)
	(arc
		(start 338.445094 -260.373622)
		(mid 338.386975 -260.223381)
		(end 338.271104 -260.111494)
		(width 0.088646)
		(layer "In2.Cu")
		(net "M_B_CPU0_SA_DQS_DN<9>")
	)
	(arc
		(start 336.38236 -260.106414)
		(mid 336.195162 -260.056271)
		(end 336.007964 -260.106414)
		(width 0.088646)
		(layer "In2.Cu")
		(net "M_B_CPU0_SA_DQS_DN<9>")
	)
	(arc
		(start 335.068164 -260.106414)
		(mid 334.785462 -260.18219)
		(end 334.50276 -260.106414)
		(width 0.088646)
		(layer "In2.Cu")
		(net "M_B_CPU0_SA_DQS_DN<9>")
	)
	(arc
		(start 336.007964 -260.106414)
		(mid 335.725262 -260.18219)
		(end 335.44256 -260.106414)
		(width 0.088646)
		(layer "In2.Cu")
		(net "M_B_CPU0_SA_DQS_DN<9>")
	)
	(segment
		(start 297.147996 -283.755592)
		(end 297.409108 -284.016704)
		(width 0.20066)
		(layer "F.Cu")
		(net "M_B_CPU0_SA_DQS_DN<8>")
	)
	(segment
		(start 291.984176 -283.33319)
		(end 292.223952 -283.33319)
		(width 0.20066)
		(layer "F.Cu")
		(net "M_B_CPU0_SA_DQS_DN<8>")
	)
	(segment
		(start 295.000426 -283.591762)
		(end 295.142666 -283.591762)
		(width 0.20066)
		(layer "F.Cu")
		(net "M_B_CPU0_SA_DQS_DN<8>")
	)
	(segment
		(start 292.92296 -283.591762)
		(end 295.000426 -283.591762)
		(width 0.1016)
		(layer "F.Cu")
		(net "M_B_CPU0_SA_DQS_DN<8>")
	)
	(segment
		(start 342.304116 -262.87222)
		(end 342.303862 -262.872474)
		(width 0.20066)
		(layer "F.Cu")
		(net "M_B_CPU0_SA_DQS_DN<8>")
	)
	(segment
		(start 295.142666 -283.591762)
		(end 295.403778 -283.33065)
		(width 0.20066)
		(layer "F.Cu")
		(net "M_B_CPU0_SA_DQS_DN<8>")
	)
	(segment
		(start 292.684962 -283.591762)
		(end 292.92296 -283.591762)
		(width 0.101854)
		(layer "F.Cu")
		(net "M_B_CPU0_SA_DQS_DN<8>")
	)
	(segment
		(start 295.8084 -283.33065)
		(end 296.444416 -283.755592)
		(width 0.20066)
		(layer "F.Cu")
		(net "M_B_CPU0_SA_DQS_DN<8>")
	)
	(segment
		(start 292.223952 -283.33319)
		(end 292.492176 -283.601414)
		(width 0.20066)
		(layer "F.Cu")
		(net "M_B_CPU0_SA_DQS_DN<8>")
	)
	(segment
		(start 299.029882 -284.016958)
		(end 299.029628 -284.016704)
		(width 0.20066)
		(layer "F.Cu")
		(net "M_B_CPU0_SA_DQS_DN<8>")
	)
	(segment
		(start 292.67531 -283.601414)
		(end 292.684962 -283.591762)
		(width 0.101854)
		(layer "F.Cu")
		(net "M_B_CPU0_SA_DQS_DN<8>")
	)
	(segment
		(start 295.403778 -283.33065)
		(end 295.8084 -283.33065)
		(width 0.20066)
		(layer "F.Cu")
		(net "M_B_CPU0_SA_DQS_DN<8>")
	)
	(segment
		(start 290.82746 -284.016704)
		(end 291.088572 -283.755592)
		(width 0.20066)
		(layer "F.Cu")
		(net "M_B_CPU0_SA_DQS_DN<8>")
	)
	(segment
		(start 297.409108 -284.016704)
		(end 297.899582 -284.016704)
		(width 0.20066)
		(layer "F.Cu")
		(net "M_B_CPU0_SA_DQS_DN<8>")
	)
	(segment
		(start 291.561774 -283.755592)
		(end 291.984176 -283.33319)
		(width 0.20066)
		(layer "F.Cu")
		(net "M_B_CPU0_SA_DQS_DN<8>")
	)
	(segment
		(start 342.304116 -262.336534)
		(end 342.304116 -262.87222)
		(width 0.20066)
		(layer "F.Cu")
		(net "M_B_CPU0_SA_DQS_DN<8>")
	)
	(segment
		(start 290.355782 -284.016704)
		(end 290.82746 -284.016704)
		(width 0.20066)
		(layer "F.Cu")
		(net "M_B_CPU0_SA_DQS_DN<8>")
	)
	(segment
		(start 291.088572 -283.755592)
		(end 291.561774 -283.755592)
		(width 0.20066)
		(layer "F.Cu")
		(net "M_B_CPU0_SA_DQS_DN<8>")
	)
	(segment
		(start 292.492176 -283.601414)
		(end 292.67531 -283.601414)
		(width 0.20066)
		(layer "F.Cu")
		(net "M_B_CPU0_SA_DQS_DN<8>")
	)
	(segment
		(start 299.029628 -284.016704)
		(end 297.899582 -284.016704)
		(width 0.20066)
		(layer "F.Cu")
		(net "M_B_CPU0_SA_DQS_DN<8>")
	)
	(segment
		(start 296.444416 -283.755592)
		(end 297.147996 -283.755592)
		(width 0.20066)
		(layer "F.Cu")
		(net "M_B_CPU0_SA_DQS_DN<8>")
	)
	(segment
		(start 339.677756 -262.551418)
		(end 339.666072 -262.544814)
		(width 0.088646)
		(layer "In4.Cu")
		(net "M_B_CPU0_SA_DQS_DN<8>")
	)
	(segment
		(start 300.387766 -283.901642)
		(end 299.809916 -283.901642)
		(width 0.18288)
		(layer "In4.Cu")
		(net "M_B_CPU0_SA_DQS_DN<8>")
	)
	(segment
		(start 310.861456 -276.845776)
		(end 310.414416 -277.292816)
		(width 0.18288)
		(layer "In4.Cu")
		(net "M_B_CPU0_SA_DQS_DN<8>")
	)
	(segment
		(start 300.768766 -283.744416)
		(end 300.387766 -283.901642)
		(width 0.18288)
		(layer "In4.Cu")
		(net "M_B_CPU0_SA_DQS_DN<8>")
	)
	(segment
		(start 337.79587 -262.550148)
		(end 337.792314 -262.548116)
		(width 0.088646)
		(layer "In4.Cu")
		(net "M_B_CPU0_SA_DQS_DN<8>")
	)
	(segment
		(start 311.75071 -275.006054)
		(end 311.534048 -275.222716)
		(width 0.18288)
		(layer "In4.Cu")
		(net "M_B_CPU0_SA_DQS_DN<8>")
	)
	(segment
		(start 327.671176 -262.77062)
		(end 325.530972 -263.657588)
		(width 0.18288)
		(layer "In4.Cu")
		(net "M_B_CPU0_SA_DQS_DN<8>")
	)
	(segment
		(start 299.299884 -283.746956)
		(end 299.029882 -284.016958)
		(width 0.18288)
		(layer "In4.Cu")
		(net "M_B_CPU0_SA_DQS_DN<8>")
	)
	(segment
		(start 331.496416 -262.623808)
		(end 331.319378 -262.623808)
		(width 0.088646)
		(layer "In4.Cu")
		(net "M_B_CPU0_SA_DQS_DN<8>")
	)
	(segment
		(start 341.933022 -262.973058)
		(end 341.555832 -263.194292)
		(width 0.088646)
		(layer "In4.Cu")
		(net "M_B_CPU0_SA_DQS_DN<8>")
	)
	(segment
		(start 330.724002 -262.77062)
		(end 327.671176 -262.77062)
		(width 0.18288)
		(layer "In4.Cu")
		(net "M_B_CPU0_SA_DQS_DN<8>")
	)
	(segment
		(start 302.741838 -282.242514)
		(end 301.937674 -282.575508)
		(width 0.18288)
		(layer "In4.Cu")
		(net "M_B_CPU0_SA_DQS_DN<8>")
	)
	(segment
		(start 340.679532 -262.58647)
		(end 340.605872 -262.544814)
		(width 0.088646)
		(layer "In4.Cu")
		(net "M_B_CPU0_SA_DQS_DN<8>")
	)
	(segment
		(start 315.901578 -273.286982)
		(end 311.75071 -275.006054)
		(width 0.18288)
		(layer "In4.Cu")
		(net "M_B_CPU0_SA_DQS_DN<8>")
	)
	(segment
		(start 306.264818 -279.889458)
		(end 304.373534 -279.889458)
		(width 0.18288)
		(layer "In4.Cu")
		(net "M_B_CPU0_SA_DQS_DN<8>")
	)
	(segment
		(start 331.23251 -262.710676)
		(end 330.81214 -262.710676)
		(width 0.088646)
		(layer "In4.Cu")
		(net "M_B_CPU0_SA_DQS_DN<8>")
	)
	(segment
		(start 331.778864 -262.548116)
		(end 331.77861 -262.547862)
		(width 0.088646)
		(layer "In4.Cu")
		(net "M_B_CPU0_SA_DQS_DN<8>")
	)
	(segment
		(start 336.857086 -262.550656)
		(end 336.85226 -262.548116)
		(width 0.088646)
		(layer "In4.Cu")
		(net "M_B_CPU0_SA_DQS_DN<8>")
	)
	(segment
		(start 330.752196 -262.77062)
		(end 330.724002 -262.77062)
		(width 0.088646)
		(layer "In4.Cu")
		(net "M_B_CPU0_SA_DQS_DN<8>")
	)
	(segment
		(start 308.206648 -279.08504)
		(end 306.264818 -279.889458)
		(width 0.18288)
		(layer "In4.Cu")
		(net "M_B_CPU0_SA_DQS_DN<8>")
	)
	(segment
		(start 299.65523 -283.746956)
		(end 299.299884 -283.746956)
		(width 0.18288)
		(layer "In4.Cu")
		(net "M_B_CPU0_SA_DQS_DN<8>")
	)
	(segment
		(start 341.04707 -263.101074)
		(end 340.882732 -262.936736)
		(width 0.088646)
		(layer "In4.Cu")
		(net "M_B_CPU0_SA_DQS_DN<8>")
	)
	(segment
		(start 325.530972 -263.657588)
		(end 315.901578 -273.286982)
		(width 0.18288)
		(layer "In4.Cu")
		(net "M_B_CPU0_SA_DQS_DN<8>")
	)
	(segment
		(start 311.534048 -275.222716)
		(end 310.861456 -276.845776)
		(width 0.18288)
		(layer "In4.Cu")
		(net "M_B_CPU0_SA_DQS_DN<8>")
	)
	(segment
		(start 338.737956 -262.551418)
		(end 338.726272 -262.544814)
		(width 0.088646)
		(layer "In4.Cu")
		(net "M_B_CPU0_SA_DQS_DN<8>")
	)
	(segment
		(start 309.704994 -277.586694)
		(end 308.206648 -279.08504)
		(width 0.18288)
		(layer "In4.Cu")
		(net "M_B_CPU0_SA_DQS_DN<8>")
	)
	(segment
		(start 301.937674 -282.575508)
		(end 300.768766 -283.744416)
		(width 0.18288)
		(layer "In4.Cu")
		(net "M_B_CPU0_SA_DQS_DN<8>")
	)
	(segment
		(start 304.373534 -279.889458)
		(end 303.570132 -280.69286)
		(width 0.18288)
		(layer "In4.Cu")
		(net "M_B_CPU0_SA_DQS_DN<8>")
	)
	(segment
		(start 330.81214 -262.710676)
		(end 330.752196 -262.77062)
		(width 0.088646)
		(layer "In4.Cu")
		(net "M_B_CPU0_SA_DQS_DN<8>")
	)
	(segment
		(start 310.414416 -277.292816)
		(end 309.704994 -277.586694)
		(width 0.18288)
		(layer "In4.Cu")
		(net "M_B_CPU0_SA_DQS_DN<8>")
	)
	(segment
		(start 303.059084 -281.925268)
		(end 302.741838 -282.242514)
		(width 0.18288)
		(layer "In4.Cu")
		(net "M_B_CPU0_SA_DQS_DN<8>")
	)
	(segment
		(start 331.319378 -262.623808)
		(end 331.23251 -262.710676)
		(width 0.088646)
		(layer "In4.Cu")
		(net "M_B_CPU0_SA_DQS_DN<8>")
	)
	(segment
		(start 303.570132 -280.69286)
		(end 303.059084 -281.925268)
		(width 0.18288)
		(layer "In4.Cu")
		(net "M_B_CPU0_SA_DQS_DN<8>")
	)
	(segment
		(start 299.809916 -283.901642)
		(end 299.65523 -283.746956)
		(width 0.18288)
		(layer "In4.Cu")
		(net "M_B_CPU0_SA_DQS_DN<8>")
	)
	(arc
		(start 337.792314 -262.548116)
		(mid 337.605006 -262.497973)
		(end 337.417664 -262.548116)
		(width 0.088646)
		(layer "In4.Cu")
		(net "M_B_CPU0_SA_DQS_DN<8>")
	)
	(arc
		(start 332.15326 -262.548116)
		(mid 331.966062 -262.497973)
		(end 331.778864 -262.548116)
		(width 0.088646)
		(layer "In4.Cu")
		(net "M_B_CPU0_SA_DQS_DN<8>")
	)
	(arc
		(start 333.09306 -262.548116)
		(mid 332.905862 -262.497973)
		(end 332.718664 -262.548116)
		(width 0.088646)
		(layer "In4.Cu")
		(net "M_B_CPU0_SA_DQS_DN<8>")
	)
	(arc
		(start 334.598264 -262.548116)
		(mid 334.315562 -262.623892)
		(end 334.03286 -262.548116)
		(width 0.088646)
		(layer "In4.Cu")
		(net "M_B_CPU0_SA_DQS_DN<8>")
	)
	(arc
		(start 340.831932 -262.814054)
		(mid 340.801832 -262.722708)
		(end 340.74862 -262.642604)
		(width 0.088646)
		(layer "In4.Cu")
		(net "M_B_CPU0_SA_DQS_DN<8>")
	)
	(arc
		(start 341.20963 -263.213596)
		(mid 341.123274 -263.164667)
		(end 341.04707 -263.101074)
		(width 0.088646)
		(layer "In4.Cu")
		(net "M_B_CPU0_SA_DQS_DN<8>")
	)
	(arc
		(start 339.666072 -262.544814)
		(mid 339.481217 -262.497864)
		(end 339.297264 -262.548116)
		(width 0.088646)
		(layer "In4.Cu")
		(net "M_B_CPU0_SA_DQS_DN<8>")
	)
	(arc
		(start 342.303862 -262.872474)
		(mid 342.111732 -262.898031)
		(end 341.933022 -262.973058)
		(width 0.088646)
		(layer "In4.Cu")
		(net "M_B_CPU0_SA_DQS_DN<8>")
	)
	(arc
		(start 338.726272 -262.544814)
		(mid 338.541417 -262.497864)
		(end 338.357464 -262.548116)
		(width 0.088646)
		(layer "In4.Cu")
		(net "M_B_CPU0_SA_DQS_DN<8>")
	)
	(arc
		(start 333.658464 -262.548116)
		(mid 333.375762 -262.623892)
		(end 333.09306 -262.548116)
		(width 0.088646)
		(layer "In4.Cu")
		(net "M_B_CPU0_SA_DQS_DN<8>")
	)
	(arc
		(start 340.74862 -262.642604)
		(mid 340.716454 -262.611607)
		(end 340.679532 -262.58647)
		(width 0.088646)
		(layer "In4.Cu")
		(net "M_B_CPU0_SA_DQS_DN<8>")
	)
	(arc
		(start 339.297264 -262.548116)
		(mid 339.018061 -262.623756)
		(end 338.737956 -262.551418)
		(width 0.088646)
		(layer "In4.Cu")
		(net "M_B_CPU0_SA_DQS_DN<8>")
	)
	(arc
		(start 336.85226 -262.548116)
		(mid 336.665062 -262.497973)
		(end 336.477864 -262.548116)
		(width 0.088646)
		(layer "In4.Cu")
		(net "M_B_CPU0_SA_DQS_DN<8>")
	)
	(arc
		(start 336.477864 -262.548116)
		(mid 336.195162 -262.623892)
		(end 335.91246 -262.548116)
		(width 0.088646)
		(layer "In4.Cu")
		(net "M_B_CPU0_SA_DQS_DN<8>")
	)
	(arc
		(start 341.490808 -263.225026)
		(mid 341.349105 -263.246722)
		(end 341.20963 -263.213596)
		(width 0.088646)
		(layer "In4.Cu")
		(net "M_B_CPU0_SA_DQS_DN<8>")
	)
	(arc
		(start 332.718664 -262.548116)
		(mid 332.435962 -262.623892)
		(end 332.15326 -262.548116)
		(width 0.088646)
		(layer "In4.Cu")
		(net "M_B_CPU0_SA_DQS_DN<8>")
	)
	(arc
		(start 340.605872 -262.544814)
		(mid 340.421017 -262.497864)
		(end 340.237064 -262.548116)
		(width 0.088646)
		(layer "In4.Cu")
		(net "M_B_CPU0_SA_DQS_DN<8>")
	)
	(arc
		(start 334.97266 -262.548116)
		(mid 334.785462 -262.497973)
		(end 334.598264 -262.548116)
		(width 0.088646)
		(layer "In4.Cu")
		(net "M_B_CPU0_SA_DQS_DN<8>")
	)
	(arc
		(start 335.91246 -262.548116)
		(mid 335.725262 -262.497973)
		(end 335.538064 -262.548116)
		(width 0.088646)
		(layer "In4.Cu")
		(net "M_B_CPU0_SA_DQS_DN<8>")
	)
	(arc
		(start 340.237064 -262.548116)
		(mid 339.957861 -262.623756)
		(end 339.677756 -262.551418)
		(width 0.088646)
		(layer "In4.Cu")
		(net "M_B_CPU0_SA_DQS_DN<8>")
	)
	(arc
		(start 335.538064 -262.548116)
		(mid 335.255362 -262.623892)
		(end 334.97266 -262.548116)
		(width 0.088646)
		(layer "In4.Cu")
		(net "M_B_CPU0_SA_DQS_DN<8>")
	)
	(arc
		(start 337.417664 -262.548116)
		(mid 337.13772 -262.62376)
		(end 336.857086 -262.550656)
		(width 0.088646)
		(layer "In4.Cu")
		(net "M_B_CPU0_SA_DQS_DN<8>")
	)
	(arc
		(start 341.555832 -263.194292)
		(mid 341.524033 -263.211167)
		(end 341.490808 -263.225026)
		(width 0.088646)
		(layer "In4.Cu")
		(net "M_B_CPU0_SA_DQS_DN<8>")
	)
	(arc
		(start 338.357464 -262.548116)
		(mid 338.076953 -262.623762)
		(end 337.79587 -262.550148)
		(width 0.088646)
		(layer "In4.Cu")
		(net "M_B_CPU0_SA_DQS_DN<8>")
	)
	(arc
		(start 340.882732 -262.936736)
		(mid 340.845122 -262.880449)
		(end 340.831932 -262.814054)
		(width 0.088646)
		(layer "In4.Cu")
		(net "M_B_CPU0_SA_DQS_DN<8>")
	)
	(arc
		(start 331.77861 -262.547862)
		(mid 331.642511 -262.604411)
		(end 331.496416 -262.623808)
		(width 0.088646)
		(layer "In4.Cu")
		(net "M_B_CPU0_SA_DQS_DN<8>")
	)
	(arc
		(start 334.03286 -262.548116)
		(mid 333.845662 -262.497973)
		(end 333.658464 -262.548116)
		(width 0.088646)
		(layer "In4.Cu")
		(net "M_B_CPU0_SA_DQS_DN<8>")
	)
	(segment
		(start 290.355782 -293.366698)
		(end 290.82746 -293.366698)
		(width 0.20066)
		(layer "F.Cu")
		(net "M_B_CPU0_SA_DQS_DN<7>")
	)
	(segment
		(start 295.142666 -292.941756)
		(end 295.403778 -292.680644)
		(width 0.20066)
		(layer "F.Cu")
		(net "M_B_CPU0_SA_DQS_DN<7>")
	)
	(segment
		(start 295.8084 -292.680644)
		(end 296.444416 -293.105586)
		(width 0.20066)
		(layer "F.Cu")
		(net "M_B_CPU0_SA_DQS_DN<7>")
	)
	(segment
		(start 292.492176 -292.951408)
		(end 292.67531 -292.951408)
		(width 0.20066)
		(layer "F.Cu")
		(net "M_B_CPU0_SA_DQS_DN<7>")
	)
	(segment
		(start 296.444416 -293.105586)
		(end 297.147996 -293.105586)
		(width 0.20066)
		(layer "F.Cu")
		(net "M_B_CPU0_SA_DQS_DN<7>")
	)
	(segment
		(start 290.82746 -293.366698)
		(end 291.088572 -293.105586)
		(width 0.20066)
		(layer "F.Cu")
		(net "M_B_CPU0_SA_DQS_DN<7>")
	)
	(segment
		(start 292.92296 -292.941756)
		(end 295.000426 -292.941756)
		(width 0.1016)
		(layer "F.Cu")
		(net "M_B_CPU0_SA_DQS_DN<7>")
	)
	(segment
		(start 299.029882 -293.366952)
		(end 299.029628 -293.366698)
		(width 0.20066)
		(layer "F.Cu")
		(net "M_B_CPU0_SA_DQS_DN<7>")
	)
	(segment
		(start 295.000426 -292.941756)
		(end 295.142666 -292.941756)
		(width 0.20066)
		(layer "F.Cu")
		(net "M_B_CPU0_SA_DQS_DN<7>")
	)
	(segment
		(start 297.147996 -293.105586)
		(end 297.409108 -293.366698)
		(width 0.20066)
		(layer "F.Cu")
		(net "M_B_CPU0_SA_DQS_DN<7>")
	)
	(segment
		(start 292.67531 -292.951408)
		(end 292.676834 -292.951408)
		(width 0.101854)
		(layer "F.Cu")
		(net "M_B_CPU0_SA_DQS_DN<7>")
	)
	(segment
		(start 292.686486 -292.941756)
		(end 292.92296 -292.941756)
		(width 0.101854)
		(layer "F.Cu")
		(net "M_B_CPU0_SA_DQS_DN<7>")
	)
	(segment
		(start 295.403778 -292.680644)
		(end 295.8084 -292.680644)
		(width 0.20066)
		(layer "F.Cu")
		(net "M_B_CPU0_SA_DQS_DN<7>")
	)
	(segment
		(start 338.074762 -264.778236)
		(end 338.074762 -265.314176)
		(width 0.20066)
		(layer "F.Cu")
		(net "M_B_CPU0_SA_DQS_DN<7>")
	)
	(segment
		(start 291.561774 -293.105586)
		(end 291.984176 -292.683184)
		(width 0.20066)
		(layer "F.Cu")
		(net "M_B_CPU0_SA_DQS_DN<7>")
	)
	(segment
		(start 292.676834 -292.951408)
		(end 292.686486 -292.941756)
		(width 0.101854)
		(layer "F.Cu")
		(net "M_B_CPU0_SA_DQS_DN<7>")
	)
	(segment
		(start 299.029628 -293.366698)
		(end 297.899582 -293.366698)
		(width 0.20066)
		(layer "F.Cu")
		(net "M_B_CPU0_SA_DQS_DN<7>")
	)
	(segment
		(start 291.984176 -292.683184)
		(end 292.223952 -292.683184)
		(width 0.20066)
		(layer "F.Cu")
		(net "M_B_CPU0_SA_DQS_DN<7>")
	)
	(segment
		(start 291.088572 -293.105586)
		(end 291.561774 -293.105586)
		(width 0.20066)
		(layer "F.Cu")
		(net "M_B_CPU0_SA_DQS_DN<7>")
	)
	(segment
		(start 292.223952 -292.683184)
		(end 292.492176 -292.951408)
		(width 0.20066)
		(layer "F.Cu")
		(net "M_B_CPU0_SA_DQS_DN<7>")
	)
	(segment
		(start 297.409108 -293.366698)
		(end 297.899582 -293.366698)
		(width 0.20066)
		(layer "F.Cu")
		(net "M_B_CPU0_SA_DQS_DN<7>")
	)
	(segment
		(start 303.585626 -290.808664)
		(end 303.422812 -290.875974)
		(width 0.18288)
		(layer "In2.Cu")
		(net "M_B_CPU0_SA_DQS_DN<7>")
	)
	(segment
		(start 310.015382 -285.29026)
		(end 309.81523 -285.490412)
		(width 0.16002)
		(layer "In2.Cu")
		(net "M_B_CPU0_SA_DQS_DN<7>")
	)
	(segment
		(start 302.413924 -292.165786)
		(end 302.217328 -292.362382)
		(width 0.16002)
		(layer "In2.Cu")
		(net "M_B_CPU0_SA_DQS_DN<7>")
	)
	(segment
		(start 300.255178 -293.30777)
		(end 299.708824 -293.30777)
		(width 0.18288)
		(layer "In2.Cu")
		(net "M_B_CPU0_SA_DQS_DN<7>")
	)
	(segment
		(start 304.036984 -289.393884)
		(end 303.728374 -290.138866)
		(width 0.18288)
		(layer "In2.Cu")
		(net "M_B_CPU0_SA_DQS_DN<7>")
	)
	(segment
		(start 299.534072 -293.133018)
		(end 299.263816 -293.133018)
		(width 0.18288)
		(layer "In2.Cu")
		(net "M_B_CPU0_SA_DQS_DN<7>")
	)
	(segment
		(start 300.472602 -293.07409)
		(end 300.472602 -293.090346)
		(width 0.16002)
		(layer "In2.Cu")
		(net "M_B_CPU0_SA_DQS_DN<7>")
	)
	(segment
		(start 299.263816 -293.133018)
		(end 299.029882 -293.366952)
		(width 0.18288)
		(layer "In2.Cu")
		(net "M_B_CPU0_SA_DQS_DN<7>")
	)
	(segment
		(start 308.164484 -286.14878)
		(end 307.96484 -286.348424)
		(width 0.16002)
		(layer "In2.Cu")
		(net "M_B_CPU0_SA_DQS_DN<7>")
	)
	(segment
		(start 313.61761 -282.66771)
		(end 312.365898 -282.66771)
		(width 0.18288)
		(layer "In2.Cu")
		(net "M_B_CPU0_SA_DQS_DN<7>")
	)
	(segment
		(start 300.688502 -292.874446)
		(end 300.672246 -292.874446)
		(width 0.16002)
		(layer "In2.Cu")
		(net "M_B_CPU0_SA_DQS_DN<7>")
	)
	(segment
		(start 314.61964 -283.135578)
		(end 314.085478 -283.135578)
		(width 0.18288)
		(layer "In2.Cu")
		(net "M_B_CPU0_SA_DQS_DN<7>")
	)
	(segment
		(start 301.960788 -292.63467)
		(end 300.928278 -292.63467)
		(width 0.18288)
		(layer "In2.Cu")
		(net "M_B_CPU0_SA_DQS_DN<7>")
	)
	(segment
		(start 309.462932 -285.858458)
		(end 308.471062 -285.858458)
		(width 0.18288)
		(layer "In2.Cu")
		(net "M_B_CPU0_SA_DQS_DN<7>")
	)
	(segment
		(start 310.833516 -284.200092)
		(end 310.250586 -284.783022)
		(width 0.18288)
		(layer "In2.Cu")
		(net "M_B_CPU0_SA_DQS_DN<7>")
	)
	(segment
		(start 311.39765 -283.81198)
		(end 311.009538 -284.200092)
		(width 0.18288)
		(layer "In2.Cu")
		(net "M_B_CPU0_SA_DQS_DN<7>")
	)
	(segment
		(start 306.065428 -288.38017)
		(end 305.050698 -288.38017)
		(width 0.18288)
		(layer "In2.Cu")
		(net "M_B_CPU0_SA_DQS_DN<7>")
	)
	(segment
		(start 310.250586 -285.070804)
		(end 310.059324 -285.262066)
		(width 0.18288)
		(layer "In2.Cu")
		(net "M_B_CPU0_SA_DQS_DN<7>")
	)
	(segment
		(start 313.696096 -282.746196)
		(end 313.667902 -282.718002)
		(width 0.16002)
		(layer "In2.Cu")
		(net "M_B_CPU0_SA_DQS_DN<7>")
	)
	(segment
		(start 330.144374 -266.561316)
		(end 330.144374 -266.646152)
		(width 0.088646)
		(layer "In2.Cu")
		(net "M_B_CPU0_SA_DQS_DN<7>")
	)
	(segment
		(start 313.667902 -282.718002)
		(end 313.61761 -282.66771)
		(width 0.18288)
		(layer "In2.Cu")
		(net "M_B_CPU0_SA_DQS_DN<7>")
	)
	(segment
		(start 314.085478 -283.135578)
		(end 313.94019 -282.99029)
		(width 0.18288)
		(layer "In2.Cu")
		(net "M_B_CPU0_SA_DQS_DN<7>")
	)
	(segment
		(start 303.213008 -291.382704)
		(end 302.509936 -292.085522)
		(width 0.18288)
		(layer "In2.Cu")
		(net "M_B_CPU0_SA_DQS_DN<7>")
	)
	(segment
		(start 313.712352 -282.746196)
		(end 313.696096 -282.746196)
		(width 0.16002)
		(layer "In2.Cu")
		(net "M_B_CPU0_SA_DQS_DN<7>")
	)
	(segment
		(start 312.211974 -282.805378)
		(end 312.01233 -283.005022)
		(width 0.16002)
		(layer "In2.Cu")
		(net "M_B_CPU0_SA_DQS_DN<7>")
	)
	(segment
		(start 317.838074 -279.465786)
		(end 315.281818 -282.022042)
		(width 0.18288)
		(layer "In2.Cu")
		(net "M_B_CPU0_SA_DQS_DN<7>")
	)
	(segment
		(start 307.96484 -286.36468)
		(end 307.936646 -286.392874)
		(width 0.16002)
		(layer "In2.Cu")
		(net "M_B_CPU0_SA_DQS_DN<7>")
	)
	(segment
		(start 315.281818 -282.022042)
		(end 315.281818 -282.4734)
		(width 0.18288)
		(layer "In2.Cu")
		(net "M_B_CPU0_SA_DQS_DN<7>")
	)
	(segment
		(start 305.050698 -288.38017)
		(end 304.762662 -288.668206)
		(width 0.18288)
		(layer "In2.Cu")
		(net "M_B_CPU0_SA_DQS_DN<7>")
	)
	(segment
		(start 304.490374 -288.940494)
		(end 304.036984 -289.393884)
		(width 0.18288)
		(layer "In2.Cu")
		(net "M_B_CPU0_SA_DQS_DN<7>")
	)
	(segment
		(start 302.217328 -292.362382)
		(end 302.217328 -292.37813)
		(width 0.16002)
		(layer "In2.Cu")
		(net "M_B_CPU0_SA_DQS_DN<7>")
	)
	(segment
		(start 306.517548 -287.912302)
		(end 306.317396 -288.112454)
		(width 0.16002)
		(layer "In2.Cu")
		(net "M_B_CPU0_SA_DQS_DN<7>")
	)
	(segment
		(start 331.639926 -265.065764)
		(end 330.144374 -266.561316)
		(width 0.088646)
		(layer "In2.Cu")
		(net "M_B_CPU0_SA_DQS_DN<7>")
	)
	(segment
		(start 308.471062 -285.858458)
		(end 308.208934 -286.120586)
		(width 0.18288)
		(layer "In2.Cu")
		(net "M_B_CPU0_SA_DQS_DN<7>")
	)
	(segment
		(start 302.217328 -292.37813)
		(end 302.189134 -292.406324)
		(width 0.16002)
		(layer "In2.Cu")
		(net "M_B_CPU0_SA_DQS_DN<7>")
	)
	(segment
		(start 303.728374 -290.138866)
		(end 303.795684 -290.301426)
		(width 0.18288)
		(layer "In2.Cu")
		(net "M_B_CPU0_SA_DQS_DN<7>")
	)
	(segment
		(start 311.39765 -283.635958)
		(end 311.39765 -283.81198)
		(width 0.18288)
		(layer "In2.Cu")
		(net "M_B_CPU0_SA_DQS_DN<7>")
	)
	(segment
		(start 304.718212 -288.6964)
		(end 304.518568 -288.896044)
		(width 0.16002)
		(layer "In2.Cu")
		(net "M_B_CPU0_SA_DQS_DN<7>")
	)
	(segment
		(start 306.317396 -288.112454)
		(end 306.317396 -288.128202)
		(width 0.16002)
		(layer "In2.Cu")
		(net "M_B_CPU0_SA_DQS_DN<7>")
	)
	(segment
		(start 330.144374 -266.646152)
		(end 328.295 -268.495526)
		(width 0.18288)
		(layer "In2.Cu")
		(net "M_B_CPU0_SA_DQS_DN<7>")
	)
	(segment
		(start 306.533296 -287.912302)
		(end 306.517548 -287.912302)
		(width 0.16002)
		(layer "In2.Cu")
		(net "M_B_CPU0_SA_DQS_DN<7>")
	)
	(segment
		(start 313.911996 -282.94584)
		(end 313.712352 -282.746196)
		(width 0.16002)
		(layer "In2.Cu")
		(net "M_B_CPU0_SA_DQS_DN<7>")
	)
	(segment
		(start 300.672246 -292.874446)
		(end 300.472602 -293.07409)
		(width 0.16002)
		(layer "In2.Cu")
		(net "M_B_CPU0_SA_DQS_DN<7>")
	)
	(segment
		(start 304.518568 -288.896044)
		(end 304.518568 -288.9123)
		(width 0.16002)
		(layer "In2.Cu")
		(net "M_B_CPU0_SA_DQS_DN<7>")
	)
	(segment
		(start 309.81523 -285.490412)
		(end 309.81523 -285.50616)
		(width 0.16002)
		(layer "In2.Cu")
		(net "M_B_CPU0_SA_DQS_DN<7>")
	)
	(segment
		(start 302.429672 -292.165786)
		(end 302.413924 -292.165786)
		(width 0.16002)
		(layer "In2.Cu")
		(net "M_B_CPU0_SA_DQS_DN<7>")
	)
	(segment
		(start 303.795684 -290.301426)
		(end 303.585626 -290.808664)
		(width 0.18288)
		(layer "In2.Cu")
		(net "M_B_CPU0_SA_DQS_DN<7>")
	)
	(segment
		(start 338.387436 -265.314176)
		(end 338.44484 -265.256772)
		(width 0.088646)
		(layer "In2.Cu")
		(net "M_B_CPU0_SA_DQS_DN<7>")
	)
	(segment
		(start 338.074762 -265.314176)
		(end 338.387436 -265.314176)
		(width 0.088646)
		(layer "In2.Cu")
		(net "M_B_CPU0_SA_DQS_DN<7>")
	)
	(segment
		(start 307.108606 -287.220914)
		(end 307.108606 -287.336992)
		(width 0.18288)
		(layer "In2.Cu")
		(net "M_B_CPU0_SA_DQS_DN<7>")
	)
	(segment
		(start 308.208934 -286.120586)
		(end 308.18074 -286.14878)
		(width 0.16002)
		(layer "In2.Cu")
		(net "M_B_CPU0_SA_DQS_DN<7>")
	)
	(segment
		(start 306.289202 -288.156396)
		(end 306.065428 -288.38017)
		(width 0.18288)
		(layer "In2.Cu")
		(net "M_B_CPU0_SA_DQS_DN<7>")
	)
	(segment
		(start 313.911996 -282.962096)
		(end 313.911996 -282.94584)
		(width 0.16002)
		(layer "In2.Cu")
		(net "M_B_CPU0_SA_DQS_DN<7>")
	)
	(segment
		(start 309.81523 -285.50616)
		(end 309.787036 -285.534354)
		(width 0.16002)
		(layer "In2.Cu")
		(net "M_B_CPU0_SA_DQS_DN<7>")
	)
	(segment
		(start 317.838074 -278.351996)
		(end 317.838074 -279.465786)
		(width 0.18288)
		(layer "In2.Cu")
		(net "M_B_CPU0_SA_DQS_DN<7>")
	)
	(segment
		(start 306.56149 -287.884108)
		(end 306.533296 -287.912302)
		(width 0.16002)
		(layer "In2.Cu")
		(net "M_B_CPU0_SA_DQS_DN<7>")
	)
	(segment
		(start 312.256424 -282.777184)
		(end 312.22823 -282.805378)
		(width 0.16002)
		(layer "In2.Cu")
		(net "M_B_CPU0_SA_DQS_DN<7>")
	)
	(segment
		(start 327.267316 -268.922754)
		(end 317.838074 -278.351996)
		(width 0.18288)
		(layer "In2.Cu")
		(net "M_B_CPU0_SA_DQS_DN<7>")
	)
	(segment
		(start 307.936646 -286.392874)
		(end 307.108606 -287.220914)
		(width 0.18288)
		(layer "In2.Cu")
		(net "M_B_CPU0_SA_DQS_DN<7>")
	)
	(segment
		(start 307.96484 -286.348424)
		(end 307.96484 -286.36468)
		(width 0.16002)
		(layer "In2.Cu")
		(net "M_B_CPU0_SA_DQS_DN<7>")
	)
	(segment
		(start 306.317396 -288.128202)
		(end 306.289202 -288.156396)
		(width 0.16002)
		(layer "In2.Cu")
		(net "M_B_CPU0_SA_DQS_DN<7>")
	)
	(segment
		(start 304.734468 -288.6964)
		(end 304.718212 -288.6964)
		(width 0.16002)
		(layer "In2.Cu")
		(net "M_B_CPU0_SA_DQS_DN<7>")
	)
	(segment
		(start 309.787036 -285.534354)
		(end 309.462932 -285.858458)
		(width 0.18288)
		(layer "In2.Cu")
		(net "M_B_CPU0_SA_DQS_DN<7>")
	)
	(segment
		(start 302.189134 -292.406324)
		(end 301.960788 -292.63467)
		(width 0.18288)
		(layer "In2.Cu")
		(net "M_B_CPU0_SA_DQS_DN<7>")
	)
	(segment
		(start 299.708824 -293.30777)
		(end 299.534072 -293.133018)
		(width 0.18288)
		(layer "In2.Cu")
		(net "M_B_CPU0_SA_DQS_DN<7>")
	)
	(segment
		(start 310.059324 -285.262066)
		(end 310.03113 -285.29026)
		(width 0.16002)
		(layer "In2.Cu")
		(net "M_B_CPU0_SA_DQS_DN<7>")
	)
	(segment
		(start 328.295 -268.495526)
		(end 327.267316 -268.922754)
		(width 0.18288)
		(layer "In2.Cu")
		(net "M_B_CPU0_SA_DQS_DN<7>")
	)
	(segment
		(start 300.716696 -292.846252)
		(end 300.688502 -292.874446)
		(width 0.16002)
		(layer "In2.Cu")
		(net "M_B_CPU0_SA_DQS_DN<7>")
	)
	(segment
		(start 304.518568 -288.9123)
		(end 304.490374 -288.940494)
		(width 0.16002)
		(layer "In2.Cu")
		(net "M_B_CPU0_SA_DQS_DN<7>")
	)
	(segment
		(start 331.96657 -265.065764)
		(end 331.639926 -265.065764)
		(width 0.088646)
		(layer "In2.Cu")
		(net "M_B_CPU0_SA_DQS_DN<7>")
	)
	(segment
		(start 315.281818 -282.4734)
		(end 314.61964 -283.135578)
		(width 0.18288)
		(layer "In2.Cu")
		(net "M_B_CPU0_SA_DQS_DN<7>")
	)
	(segment
		(start 312.01233 -283.021278)
		(end 311.984136 -283.049472)
		(width 0.16002)
		(layer "In2.Cu")
		(net "M_B_CPU0_SA_DQS_DN<7>")
	)
	(segment
		(start 302.509936 -292.085522)
		(end 302.461422 -292.134036)
		(width 0.18288)
		(layer "In2.Cu")
		(net "M_B_CPU0_SA_DQS_DN<7>")
	)
	(segment
		(start 310.03113 -285.29026)
		(end 310.015382 -285.29026)
		(width 0.16002)
		(layer "In2.Cu")
		(net "M_B_CPU0_SA_DQS_DN<7>")
	)
	(segment
		(start 311.984136 -283.049472)
		(end 311.39765 -283.635958)
		(width 0.18288)
		(layer "In2.Cu")
		(net "M_B_CPU0_SA_DQS_DN<7>")
	)
	(segment
		(start 303.422812 -290.875974)
		(end 303.213008 -291.382704)
		(width 0.18288)
		(layer "In2.Cu")
		(net "M_B_CPU0_SA_DQS_DN<7>")
	)
	(segment
		(start 312.01233 -283.005022)
		(end 312.01233 -283.021278)
		(width 0.16002)
		(layer "In2.Cu")
		(net "M_B_CPU0_SA_DQS_DN<7>")
	)
	(segment
		(start 311.009538 -284.200092)
		(end 310.833516 -284.200092)
		(width 0.18288)
		(layer "In2.Cu")
		(net "M_B_CPU0_SA_DQS_DN<7>")
	)
	(segment
		(start 300.928278 -292.63467)
		(end 300.716696 -292.846252)
		(width 0.18288)
		(layer "In2.Cu")
		(net "M_B_CPU0_SA_DQS_DN<7>")
	)
	(segment
		(start 312.22823 -282.805378)
		(end 312.211974 -282.805378)
		(width 0.16002)
		(layer "In2.Cu")
		(net "M_B_CPU0_SA_DQS_DN<7>")
	)
	(segment
		(start 300.444408 -293.11854)
		(end 300.255178 -293.30777)
		(width 0.18288)
		(layer "In2.Cu")
		(net "M_B_CPU0_SA_DQS_DN<7>")
	)
	(segment
		(start 312.365898 -282.66771)
		(end 312.256424 -282.777184)
		(width 0.18288)
		(layer "In2.Cu")
		(net "M_B_CPU0_SA_DQS_DN<7>")
	)
	(segment
		(start 304.762662 -288.668206)
		(end 304.734468 -288.6964)
		(width 0.16002)
		(layer "In2.Cu")
		(net "M_B_CPU0_SA_DQS_DN<7>")
	)
	(segment
		(start 313.94019 -282.99029)
		(end 313.911996 -282.962096)
		(width 0.16002)
		(layer "In2.Cu")
		(net "M_B_CPU0_SA_DQS_DN<7>")
	)
	(segment
		(start 300.472602 -293.090346)
		(end 300.444408 -293.11854)
		(width 0.16002)
		(layer "In2.Cu")
		(net "M_B_CPU0_SA_DQS_DN<7>")
	)
	(segment
		(start 338.27085 -264.994898)
		(end 338.26196 -264.989818)
		(width 0.088646)
		(layer "In2.Cu")
		(net "M_B_CPU0_SA_DQS_DN<7>")
	)
	(segment
		(start 307.108606 -287.336992)
		(end 306.56149 -287.884108)
		(width 0.18288)
		(layer "In2.Cu")
		(net "M_B_CPU0_SA_DQS_DN<7>")
	)
	(segment
		(start 337.887564 -264.989818)
		(end 337.88731 -264.989564)
		(width 0.088646)
		(layer "In2.Cu")
		(net "M_B_CPU0_SA_DQS_DN<7>")
	)
	(segment
		(start 308.18074 -286.14878)
		(end 308.164484 -286.14878)
		(width 0.16002)
		(layer "In2.Cu")
		(net "M_B_CPU0_SA_DQS_DN<7>")
	)
	(segment
		(start 310.250586 -284.783022)
		(end 310.250586 -285.070804)
		(width 0.18288)
		(layer "In2.Cu")
		(net "M_B_CPU0_SA_DQS_DN<7>")
	)
	(segment
		(start 302.461422 -292.134036)
		(end 302.429672 -292.165786)
		(width 0.16002)
		(layer "In2.Cu")
		(net "M_B_CPU0_SA_DQS_DN<7>")
	)
	(arc
		(start 337.88731 -264.989564)
		(mid 337.604862 -265.065247)
		(end 337.322414 -264.989564)
		(width 0.088646)
		(layer "In2.Cu")
		(net "M_B_CPU0_SA_DQS_DN<7>")
	)
	(arc
		(start 332.623414 -264.989564)
		(mid 332.436106 -264.939455)
		(end 332.248764 -264.989564)
		(width 0.088646)
		(layer "In2.Cu")
		(net "M_B_CPU0_SA_DQS_DN<7>")
	)
	(arc
		(start 334.12811 -264.989564)
		(mid 333.845662 -265.065247)
		(end 333.563214 -264.989564)
		(width 0.088646)
		(layer "In2.Cu")
		(net "M_B_CPU0_SA_DQS_DN<7>")
	)
	(arc
		(start 334.503014 -264.989564)
		(mid 334.315562 -264.939328)
		(end 334.12811 -264.989564)
		(width 0.088646)
		(layer "In2.Cu")
		(net "M_B_CPU0_SA_DQS_DN<7>")
	)
	(arc
		(start 333.563214 -264.989564)
		(mid 333.375762 -264.939328)
		(end 333.18831 -264.989564)
		(width 0.088646)
		(layer "In2.Cu")
		(net "M_B_CPU0_SA_DQS_DN<7>")
	)
	(arc
		(start 338.26196 -264.989818)
		(mid 338.074762 -264.939675)
		(end 337.887564 -264.989818)
		(width 0.088646)
		(layer "In2.Cu")
		(net "M_B_CPU0_SA_DQS_DN<7>")
	)
	(arc
		(start 332.015084 -265.063732)
		(mid 331.990849 -265.065274)
		(end 331.96657 -265.065764)
		(width 0.088646)
		(layer "In2.Cu")
		(net "M_B_CPU0_SA_DQS_DN<7>")
	)
	(arc
		(start 336.00771 -264.989564)
		(mid 335.725262 -265.065247)
		(end 335.442814 -264.989564)
		(width 0.088646)
		(layer "In2.Cu")
		(net "M_B_CPU0_SA_DQS_DN<7>")
	)
	(arc
		(start 336.382614 -264.989564)
		(mid 336.195162 -264.939328)
		(end 336.00771 -264.989564)
		(width 0.088646)
		(layer "In2.Cu")
		(net "M_B_CPU0_SA_DQS_DN<7>")
	)
	(arc
		(start 333.18831 -264.989564)
		(mid 332.905862 -265.065247)
		(end 332.623414 -264.989564)
		(width 0.088646)
		(layer "In2.Cu")
		(net "M_B_CPU0_SA_DQS_DN<7>")
	)
	(arc
		(start 337.322414 -264.989564)
		(mid 337.134962 -264.939328)
		(end 336.94751 -264.989564)
		(width 0.088646)
		(layer "In2.Cu")
		(net "M_B_CPU0_SA_DQS_DN<7>")
	)
	(arc
		(start 336.94751 -264.989564)
		(mid 336.665062 -265.065247)
		(end 336.382614 -264.989564)
		(width 0.088646)
		(layer "In2.Cu")
		(net "M_B_CPU0_SA_DQS_DN<7>")
	)
	(arc
		(start 338.44484 -265.256772)
		(mid 338.386684 -265.106659)
		(end 338.27085 -264.994898)
		(width 0.088646)
		(layer "In2.Cu")
		(net "M_B_CPU0_SA_DQS_DN<7>")
	)
	(arc
		(start 335.442814 -264.989564)
		(mid 335.255362 -264.939328)
		(end 335.06791 -264.989564)
		(width 0.088646)
		(layer "In2.Cu")
		(net "M_B_CPU0_SA_DQS_DN<7>")
	)
	(arc
		(start 332.248764 -264.989564)
		(mid 332.13599 -265.039452)
		(end 332.015084 -265.063732)
		(width 0.088646)
		(layer "In2.Cu")
		(net "M_B_CPU0_SA_DQS_DN<7>")
	)
	(arc
		(start 335.06791 -264.989564)
		(mid 334.785462 -265.065247)
		(end 334.503014 -264.989564)
		(width 0.088646)
		(layer "In2.Cu")
		(net "M_B_CPU0_SA_DQS_DN<7>")
	)
	(segment
		(start 290.355782 -302.716692)
		(end 290.82746 -302.716692)
		(width 0.20066)
		(layer "F.Cu")
		(net "M_B_CPU0_SA_DQS_DN<6>")
	)
	(segment
		(start 295.8084 -302.030638)
		(end 296.444416 -302.45558)
		(width 0.20066)
		(layer "F.Cu")
		(net "M_B_CPU0_SA_DQS_DN<6>")
	)
	(segment
		(start 342.304116 -272.103342)
		(end 342.304116 -272.639028)
		(width 0.20066)
		(layer "F.Cu")
		(net "M_B_CPU0_SA_DQS_DN<6>")
	)
	(segment
		(start 292.67531 -302.301402)
		(end 292.676834 -302.301402)
		(width 0.101854)
		(layer "F.Cu")
		(net "M_B_CPU0_SA_DQS_DN<6>")
	)
	(segment
		(start 295.000426 -302.29175)
		(end 295.142666 -302.29175)
		(width 0.20066)
		(layer "F.Cu")
		(net "M_B_CPU0_SA_DQS_DN<6>")
	)
	(segment
		(start 297.147996 -302.45558)
		(end 297.409108 -302.716692)
		(width 0.20066)
		(layer "F.Cu")
		(net "M_B_CPU0_SA_DQS_DN<6>")
	)
	(segment
		(start 292.676834 -302.301402)
		(end 292.686486 -302.29175)
		(width 0.101854)
		(layer "F.Cu")
		(net "M_B_CPU0_SA_DQS_DN<6>")
	)
	(segment
		(start 297.409108 -302.716692)
		(end 297.899582 -302.716692)
		(width 0.20066)
		(layer "F.Cu")
		(net "M_B_CPU0_SA_DQS_DN<6>")
	)
	(segment
		(start 299.029628 -302.716692)
		(end 297.899582 -302.716692)
		(width 0.20066)
		(layer "F.Cu")
		(net "M_B_CPU0_SA_DQS_DN<6>")
	)
	(segment
		(start 296.444416 -302.45558)
		(end 297.147996 -302.45558)
		(width 0.20066)
		(layer "F.Cu")
		(net "M_B_CPU0_SA_DQS_DN<6>")
	)
	(segment
		(start 292.492176 -302.301402)
		(end 292.67531 -302.301402)
		(width 0.20066)
		(layer "F.Cu")
		(net "M_B_CPU0_SA_DQS_DN<6>")
	)
	(segment
		(start 292.92296 -302.29175)
		(end 295.000426 -302.29175)
		(width 0.1016)
		(layer "F.Cu")
		(net "M_B_CPU0_SA_DQS_DN<6>")
	)
	(segment
		(start 299.029882 -302.716946)
		(end 299.029628 -302.716692)
		(width 0.20066)
		(layer "F.Cu")
		(net "M_B_CPU0_SA_DQS_DN<6>")
	)
	(segment
		(start 295.142666 -302.29175)
		(end 295.403778 -302.030638)
		(width 0.20066)
		(layer "F.Cu")
		(net "M_B_CPU0_SA_DQS_DN<6>")
	)
	(segment
		(start 292.223952 -302.033178)
		(end 292.492176 -302.301402)
		(width 0.20066)
		(layer "F.Cu")
		(net "M_B_CPU0_SA_DQS_DN<6>")
	)
	(segment
		(start 291.984176 -302.033178)
		(end 292.223952 -302.033178)
		(width 0.20066)
		(layer "F.Cu")
		(net "M_B_CPU0_SA_DQS_DN<6>")
	)
	(segment
		(start 290.82746 -302.716692)
		(end 291.088572 -302.45558)
		(width 0.20066)
		(layer "F.Cu")
		(net "M_B_CPU0_SA_DQS_DN<6>")
	)
	(segment
		(start 342.304116 -272.639028)
		(end 342.303862 -272.639282)
		(width 0.20066)
		(layer "F.Cu")
		(net "M_B_CPU0_SA_DQS_DN<6>")
	)
	(segment
		(start 292.686486 -302.29175)
		(end 292.92296 -302.29175)
		(width 0.101854)
		(layer "F.Cu")
		(net "M_B_CPU0_SA_DQS_DN<6>")
	)
	(segment
		(start 291.088572 -302.45558)
		(end 291.561774 -302.45558)
		(width 0.20066)
		(layer "F.Cu")
		(net "M_B_CPU0_SA_DQS_DN<6>")
	)
	(segment
		(start 291.561774 -302.45558)
		(end 291.984176 -302.033178)
		(width 0.20066)
		(layer "F.Cu")
		(net "M_B_CPU0_SA_DQS_DN<6>")
	)
	(segment
		(start 295.403778 -302.030638)
		(end 295.8084 -302.030638)
		(width 0.20066)
		(layer "F.Cu")
		(net "M_B_CPU0_SA_DQS_DN<6>")
	)
	(segment
		(start 333.661258 -273.941032)
		(end 333.658464 -273.942556)
		(width 0.088646)
		(layer "In4.Cu")
		(net "M_B_CPU0_SA_DQS_DN<6>")
	)
	(segment
		(start 309.518812 -298.616624)
		(end 308.922928 -298.616624)
		(width 0.18288)
		(layer "In4.Cu")
		(net "M_B_CPU0_SA_DQS_DN<6>")
	)
	(segment
		(start 333.186024 -274.757896)
		(end 333.17942 -274.761452)
		(width 0.088646)
		(layer "In4.Cu")
		(net "M_B_CPU0_SA_DQS_DN<6>")
	)
	(segment
		(start 313.612022 -297.17238)
		(end 312.16219 -298.622212)
		(width 0.18288)
		(layer "In4.Cu")
		(net "M_B_CPU0_SA_DQS_DN<6>")
	)
	(segment
		(start 333.66456 -273.939)
		(end 333.661258 -273.941032)
		(width 0.088646)
		(layer "In4.Cu")
		(net "M_B_CPU0_SA_DQS_DN<6>")
	)
	(segment
		(start 331.564488 -276.379686)
		(end 330.601574 -277.343108)
		(width 0.18288)
		(layer "In4.Cu")
		(net "M_B_CPU0_SA_DQS_DN<6>")
	)
	(segment
		(start 333.65694 -273.943318)
		(end 333.649574 -273.947636)
		(width 0.088646)
		(layer "In4.Cu")
		(net "M_B_CPU0_SA_DQS_DN<6>")
	)
	(segment
		(start 333.191104 -274.754848)
		(end 333.18831 -274.756372)
		(width 0.088646)
		(layer "In4.Cu")
		(net "M_B_CPU0_SA_DQS_DN<6>")
	)
	(segment
		(start 304.489358 -302.160178)
		(end 303.862994 -302.160178)
		(width 0.18288)
		(layer "In4.Cu")
		(net "M_B_CPU0_SA_DQS_DN<6>")
	)
	(segment
		(start 342.303862 -272.639282)
		(end 341.626444 -272.927064)
		(width 0.088646)
		(layer "In4.Cu")
		(net "M_B_CPU0_SA_DQS_DN<6>")
	)
	(segment
		(start 316.069472 -297.17238)
		(end 313.612022 -297.17238)
		(width 0.18288)
		(layer "In4.Cu")
		(net "M_B_CPU0_SA_DQS_DN<6>")
	)
	(segment
		(start 331.764894 -276.379686)
		(end 331.741526 -276.379686)
		(width 0.088646)
		(layer "In4.Cu")
		(net "M_B_CPU0_SA_DQS_DN<6>")
	)
	(segment
		(start 306.145438 -300.504098)
		(end 304.489358 -302.160178)
		(width 0.18288)
		(layer "In4.Cu")
		(net "M_B_CPU0_SA_DQS_DN<6>")
	)
	(segment
		(start 308.922928 -298.616624)
		(end 308.54396 -298.995592)
		(width 0.18288)
		(layer "In4.Cu")
		(net "M_B_CPU0_SA_DQS_DN<6>")
	)
	(segment
		(start 330.601574 -277.343108)
		(end 330.602336 -277.343616)
		(width 0.18288)
		(layer "In4.Cu")
		(net "M_B_CPU0_SA_DQS_DN<6>")
	)
	(segment
		(start 310.163464 -298.89196)
		(end 309.794148 -298.89196)
		(width 0.18288)
		(layer "In4.Cu")
		(net "M_B_CPU0_SA_DQS_DN<6>")
	)
	(segment
		(start 332.971394 -275.392896)
		(end 332.044548 -276.319742)
		(width 0.088646)
		(layer "In4.Cu")
		(net "M_B_CPU0_SA_DQS_DN<6>")
	)
	(segment
		(start 338.742528 -272.32102)
		(end 338.732114 -272.314924)
		(width 0.088646)
		(layer "In4.Cu")
		(net "M_B_CPU0_SA_DQS_DN<6>")
	)
	(segment
		(start 330.602336 -277.343616)
		(end 324.45452 -283.506418)
		(width 0.18288)
		(layer "In4.Cu")
		(net "M_B_CPU0_SA_DQS_DN<6>")
	)
	(segment
		(start 308.54396 -298.995592)
		(end 307.95722 -299.23867)
		(width 0.18288)
		(layer "In4.Cu")
		(net "M_B_CPU0_SA_DQS_DN<6>")
	)
	(segment
		(start 302.675798 -302.652176)
		(end 299.86224 -302.652176)
		(width 0.18288)
		(layer "In4.Cu")
		(net "M_B_CPU0_SA_DQS_DN<6>")
	)
	(segment
		(start 306.691792 -300.504098)
		(end 306.145438 -300.504098)
		(width 0.18288)
		(layer "In4.Cu")
		(net "M_B_CPU0_SA_DQS_DN<6>")
	)
	(segment
		(start 309.794148 -298.89196)
		(end 309.518812 -298.616624)
		(width 0.18288)
		(layer "In4.Cu")
		(net "M_B_CPU0_SA_DQS_DN<6>")
	)
	(segment
		(start 337.802474 -272.32102)
		(end 337.79206 -272.314924)
		(width 0.088646)
		(layer "In4.Cu")
		(net "M_B_CPU0_SA_DQS_DN<6>")
	)
	(segment
		(start 312.16219 -298.622212)
		(end 310.433212 -298.622212)
		(width 0.18288)
		(layer "In4.Cu")
		(net "M_B_CPU0_SA_DQS_DN<6>")
	)
	(segment
		(start 333.000604 -275.080984)
		(end 333.000604 -275.101812)
		(width 0.088646)
		(layer "In4.Cu")
		(net "M_B_CPU0_SA_DQS_DN<6>")
	)
	(segment
		(start 320.719704 -292.522402)
		(end 316.069472 -297.17238)
		(width 0.18288)
		(layer "In4.Cu")
		(net "M_B_CPU0_SA_DQS_DN<6>")
	)
	(segment
		(start 307.95722 -299.23867)
		(end 306.691792 -300.504098)
		(width 0.18288)
		(layer "In4.Cu")
		(net "M_B_CPU0_SA_DQS_DN<6>")
	)
	(segment
		(start 299.30471 -302.442118)
		(end 299.029882 -302.716946)
		(width 0.18288)
		(layer "In4.Cu")
		(net "M_B_CPU0_SA_DQS_DN<6>")
	)
	(segment
		(start 333.658464 -273.942556)
		(end 333.65694 -273.943318)
		(width 0.088646)
		(layer "In4.Cu")
		(net "M_B_CPU0_SA_DQS_DN<6>")
	)
	(segment
		(start 340.9061 -272.569432)
		(end 340.783926 -272.447258)
		(width 0.088646)
		(layer "In4.Cu")
		(net "M_B_CPU0_SA_DQS_DN<6>")
	)
	(segment
		(start 333.000858 -275.08073)
		(end 333.000604 -275.080984)
		(width 0.088646)
		(layer "In4.Cu")
		(net "M_B_CPU0_SA_DQS_DN<6>")
	)
	(segment
		(start 333.18831 -274.756372)
		(end 333.186786 -274.757134)
		(width 0.088646)
		(layer "In4.Cu")
		(net "M_B_CPU0_SA_DQS_DN<6>")
	)
	(segment
		(start 331.824838 -276.319742)
		(end 331.764894 -276.379686)
		(width 0.088646)
		(layer "In4.Cu")
		(net "M_B_CPU0_SA_DQS_DN<6>")
	)
	(segment
		(start 331.741526 -276.379686)
		(end 331.564488 -276.379686)
		(width 0.18288)
		(layer "In4.Cu")
		(net "M_B_CPU0_SA_DQS_DN<6>")
	)
	(segment
		(start 340.237064 -272.314924)
		(end 340.222332 -272.32356)
		(width 0.088646)
		(layer "In4.Cu")
		(net "M_B_CPU0_SA_DQS_DN<6>")
	)
	(segment
		(start 334.128618 -273.12874)
		(end 334.113632 -273.137376)
		(width 0.088646)
		(layer "In4.Cu")
		(net "M_B_CPU0_SA_DQS_DN<6>")
	)
	(segment
		(start 333.940912 -273.453098)
		(end 333.941166 -273.453098)
		(width 0.088646)
		(layer "In4.Cu")
		(net "M_B_CPU0_SA_DQS_DN<6>")
	)
	(segment
		(start 333.000604 -275.101812)
		(end 332.971394 -275.392896)
		(width 0.088646)
		(layer "In4.Cu")
		(net "M_B_CPU0_SA_DQS_DN<6>")
	)
	(segment
		(start 334.983328 -272.32102)
		(end 334.972914 -272.314924)
		(width 0.088646)
		(layer "In4.Cu")
		(net "M_B_CPU0_SA_DQS_DN<6>")
	)
	(segment
		(start 335.922874 -272.32102)
		(end 335.91246 -272.314924)
		(width 0.088646)
		(layer "In4.Cu")
		(net "M_B_CPU0_SA_DQS_DN<6>")
	)
	(segment
		(start 333.194406 -274.752816)
		(end 333.191104 -274.754848)
		(width 0.088646)
		(layer "In4.Cu")
		(net "M_B_CPU0_SA_DQS_DN<6>")
	)
	(segment
		(start 310.433212 -298.622212)
		(end 310.163464 -298.89196)
		(width 0.18288)
		(layer "In4.Cu")
		(net "M_B_CPU0_SA_DQS_DN<6>")
	)
	(segment
		(start 337.417664 -272.314924)
		(end 337.40725 -272.32102)
		(width 0.088646)
		(layer "In4.Cu")
		(net "M_B_CPU0_SA_DQS_DN<6>")
	)
	(segment
		(start 334.134714 -273.125184)
		(end 334.128618 -273.12874)
		(width 0.088646)
		(layer "In4.Cu")
		(net "M_B_CPU0_SA_DQS_DN<6>")
	)
	(segment
		(start 324.45452 -283.506418)
		(end 320.719704 -292.522402)
		(width 0.18288)
		(layer "In4.Cu")
		(net "M_B_CPU0_SA_DQS_DN<6>")
	)
	(segment
		(start 299.86224 -302.652176)
		(end 299.652182 -302.442118)
		(width 0.18288)
		(layer "In4.Cu")
		(net "M_B_CPU0_SA_DQS_DN<6>")
	)
	(segment
		(start 333.186786 -274.757134)
		(end 333.186024 -274.757896)
		(width 0.088646)
		(layer "In4.Cu")
		(net "M_B_CPU0_SA_DQS_DN<6>")
	)
	(segment
		(start 299.652182 -302.442118)
		(end 299.30471 -302.442118)
		(width 0.18288)
		(layer "In4.Cu")
		(net "M_B_CPU0_SA_DQS_DN<6>")
	)
	(segment
		(start 334.598518 -272.314924)
		(end 334.589628 -272.320004)
		(width 0.088646)
		(layer "In4.Cu")
		(net "M_B_CPU0_SA_DQS_DN<6>")
	)
	(segment
		(start 332.044548 -276.319742)
		(end 331.824838 -276.319742)
		(width 0.088646)
		(layer "In4.Cu")
		(net "M_B_CPU0_SA_DQS_DN<6>")
	)
	(segment
		(start 303.862994 -302.160178)
		(end 302.675798 -302.652176)
		(width 0.18288)
		(layer "In4.Cu")
		(net "M_B_CPU0_SA_DQS_DN<6>")
	)
	(arc
		(start 341.626444 -272.927064)
		(mid 341.586037 -272.945677)
		(end 341.546688 -272.966434)
		(width 0.088646)
		(layer "In4.Cu")
		(net "M_B_CPU0_SA_DQS_DN<6>")
	)
	(arc
		(start 334.411066 -272.639282)
		(mid 334.33715 -272.918784)
		(end 334.134714 -273.125184)
		(width 0.088646)
		(layer "In4.Cu")
		(net "M_B_CPU0_SA_DQS_DN<6>")
	)
	(arc
		(start 335.538064 -272.314924)
		(mid 335.261505 -272.390633)
		(end 334.983328 -272.32102)
		(width 0.088646)
		(layer "In4.Cu")
		(net "M_B_CPU0_SA_DQS_DN<6>")
	)
	(arc
		(start 335.91246 -272.314924)
		(mid 335.725262 -272.264781)
		(end 335.538064 -272.314924)
		(width 0.088646)
		(layer "In4.Cu")
		(net "M_B_CPU0_SA_DQS_DN<6>")
	)
	(arc
		(start 340.61146 -272.314924)
		(mid 340.424262 -272.264781)
		(end 340.237064 -272.314924)
		(width 0.088646)
		(layer "In4.Cu")
		(net "M_B_CPU0_SA_DQS_DN<6>")
	)
	(arc
		(start 340.222332 -272.32356)
		(mid 339.945891 -272.390726)
		(end 339.67166 -272.314924)
		(width 0.088646)
		(layer "In4.Cu")
		(net "M_B_CPU0_SA_DQS_DN<6>")
	)
	(arc
		(start 333.941166 -273.453098)
		(mid 333.867175 -273.732664)
		(end 333.66456 -273.939)
		(width 0.088646)
		(layer "In4.Cu")
		(net "M_B_CPU0_SA_DQS_DN<6>")
	)
	(arc
		(start 336.852514 -272.314924)
		(mid 336.665316 -272.264781)
		(end 336.478118 -272.314924)
		(width 0.088646)
		(layer "In4.Cu")
		(net "M_B_CPU0_SA_DQS_DN<6>")
	)
	(arc
		(start 334.589628 -272.320004)
		(mid 334.458714 -272.456364)
		(end 334.411066 -272.639282)
		(width 0.088646)
		(layer "In4.Cu")
		(net "M_B_CPU0_SA_DQS_DN<6>")
	)
	(arc
		(start 338.732114 -272.314924)
		(mid 338.544916 -272.264781)
		(end 338.357718 -272.314924)
		(width 0.088646)
		(layer "In4.Cu")
		(net "M_B_CPU0_SA_DQS_DN<6>")
	)
	(arc
		(start 339.67166 -272.314924)
		(mid 339.484462 -272.264781)
		(end 339.297264 -272.314924)
		(width 0.088646)
		(layer "In4.Cu")
		(net "M_B_CPU0_SA_DQS_DN<6>")
	)
	(arc
		(start 333.649574 -273.947636)
		(mid 333.51866 -274.083996)
		(end 333.471012 -274.266914)
		(width 0.088646)
		(layer "In4.Cu")
		(net "M_B_CPU0_SA_DQS_DN<6>")
	)
	(arc
		(start 336.478118 -272.314924)
		(mid 336.201305 -272.39076)
		(end 335.922874 -272.32102)
		(width 0.088646)
		(layer "In4.Cu")
		(net "M_B_CPU0_SA_DQS_DN<6>")
	)
	(arc
		(start 337.79206 -272.314924)
		(mid 337.604862 -272.264781)
		(end 337.417664 -272.314924)
		(width 0.088646)
		(layer "In4.Cu")
		(net "M_B_CPU0_SA_DQS_DN<6>")
	)
	(arc
		(start 333.471012 -274.266914)
		(mid 333.397021 -274.54648)
		(end 333.194406 -274.752816)
		(width 0.088646)
		(layer "In4.Cu")
		(net "M_B_CPU0_SA_DQS_DN<6>")
	)
	(arc
		(start 337.40725 -272.32102)
		(mid 337.129072 -272.390712)
		(end 336.852514 -272.314924)
		(width 0.088646)
		(layer "In4.Cu")
		(net "M_B_CPU0_SA_DQS_DN<6>")
	)
	(arc
		(start 340.783926 -272.447258)
		(mid 340.702039 -272.375426)
		(end 340.61146 -272.314924)
		(width 0.088646)
		(layer "In4.Cu")
		(net "M_B_CPU0_SA_DQS_DN<6>")
	)
	(arc
		(start 334.972914 -272.314924)
		(mid 334.785716 -272.264781)
		(end 334.598518 -272.314924)
		(width 0.088646)
		(layer "In4.Cu")
		(net "M_B_CPU0_SA_DQS_DN<6>")
	)
	(arc
		(start 341.002366 -272.73631)
		(mid 340.965195 -272.646552)
		(end 340.9061 -272.569432)
		(width 0.088646)
		(layer "In4.Cu")
		(net "M_B_CPU0_SA_DQS_DN<6>")
	)
	(arc
		(start 334.113632 -273.137376)
		(mid 333.986909 -273.273157)
		(end 333.940912 -273.453098)
		(width 0.088646)
		(layer "In4.Cu")
		(net "M_B_CPU0_SA_DQS_DN<6>")
	)
	(arc
		(start 339.297264 -272.314924)
		(mid 339.020705 -272.390633)
		(end 338.742528 -272.32102)
		(width 0.088646)
		(layer "In4.Cu")
		(net "M_B_CPU0_SA_DQS_DN<6>")
	)
	(arc
		(start 338.357718 -272.314924)
		(mid 338.080905 -272.39076)
		(end 337.802474 -272.32102)
		(width 0.088646)
		(layer "In4.Cu")
		(net "M_B_CPU0_SA_DQS_DN<6>")
	)
	(arc
		(start 333.17942 -274.761452)
		(mid 333.048506 -274.897812)
		(end 333.000858 -275.08073)
		(width 0.088646)
		(layer "In4.Cu")
		(net "M_B_CPU0_SA_DQS_DN<6>")
	)
	(arc
		(start 341.546688 -272.966434)
		(mid 341.218262 -272.984437)
		(end 341.002366 -272.73631)
		(width 0.088646)
		(layer "In4.Cu")
		(net "M_B_CPU0_SA_DQS_DN<6>")
	)
	(segment
		(start 292.92296 -311.641744)
		(end 292.686486 -311.641744)
		(width 0.101854)
		(layer "F.Cu")
		(net "M_B_CPU0_SA_DQS_DN<5>")
	)
	(segment
		(start 291.561774 -311.805574)
		(end 291.088572 -311.805574)
		(width 0.20066)
		(layer "F.Cu")
		(net "M_B_CPU0_SA_DQS_DN<5>")
	)
	(segment
		(start 295.142666 -311.641744)
		(end 295.000426 -311.641744)
		(width 0.20066)
		(layer "F.Cu")
		(net "M_B_CPU0_SA_DQS_DN<5>")
	)
	(segment
		(start 299.029882 -312.066686)
		(end 297.899582 -312.066686)
		(width 0.20066)
		(layer "F.Cu")
		(net "M_B_CPU0_SA_DQS_DN<5>")
	)
	(segment
		(start 295.403778 -311.380632)
		(end 295.142666 -311.641744)
		(width 0.20066)
		(layer "F.Cu")
		(net "M_B_CPU0_SA_DQS_DN<5>")
	)
	(segment
		(start 297.409108 -312.066686)
		(end 297.147996 -311.805574)
		(width 0.20066)
		(layer "F.Cu")
		(net "M_B_CPU0_SA_DQS_DN<5>")
	)
	(segment
		(start 297.147996 -311.805574)
		(end 296.444416 -311.805574)
		(width 0.20066)
		(layer "F.Cu")
		(net "M_B_CPU0_SA_DQS_DN<5>")
	)
	(segment
		(start 292.492176 -311.651396)
		(end 292.223952 -311.383172)
		(width 0.20066)
		(layer "F.Cu")
		(net "M_B_CPU0_SA_DQS_DN<5>")
	)
	(segment
		(start 291.088572 -311.805574)
		(end 290.82746 -312.066686)
		(width 0.20066)
		(layer "F.Cu")
		(net "M_B_CPU0_SA_DQS_DN<5>")
	)
	(segment
		(start 290.82746 -312.066686)
		(end 290.355782 -312.066686)
		(width 0.20066)
		(layer "F.Cu")
		(net "M_B_CPU0_SA_DQS_DN<5>")
	)
	(segment
		(start 338.074762 -274.54479)
		(end 338.074762 -275.08073)
		(width 0.20066)
		(layer "F.Cu")
		(net "M_B_CPU0_SA_DQS_DN<5>")
	)
	(segment
		(start 292.686486 -311.641744)
		(end 292.676834 -311.651396)
		(width 0.101854)
		(layer "F.Cu")
		(net "M_B_CPU0_SA_DQS_DN<5>")
	)
	(segment
		(start 296.444416 -311.805574)
		(end 295.8084 -311.380632)
		(width 0.20066)
		(layer "F.Cu")
		(net "M_B_CPU0_SA_DQS_DN<5>")
	)
	(segment
		(start 295.000426 -311.641744)
		(end 292.92296 -311.641744)
		(width 0.1016)
		(layer "F.Cu")
		(net "M_B_CPU0_SA_DQS_DN<5>")
	)
	(segment
		(start 292.67531 -311.651396)
		(end 292.492176 -311.651396)
		(width 0.20066)
		(layer "F.Cu")
		(net "M_B_CPU0_SA_DQS_DN<5>")
	)
	(segment
		(start 295.8084 -311.380632)
		(end 295.403778 -311.380632)
		(width 0.20066)
		(layer "F.Cu")
		(net "M_B_CPU0_SA_DQS_DN<5>")
	)
	(segment
		(start 292.676834 -311.651396)
		(end 292.67531 -311.651396)
		(width 0.101854)
		(layer "F.Cu")
		(net "M_B_CPU0_SA_DQS_DN<5>")
	)
	(segment
		(start 292.223952 -311.383172)
		(end 291.984176 -311.383172)
		(width 0.20066)
		(layer "F.Cu")
		(net "M_B_CPU0_SA_DQS_DN<5>")
	)
	(segment
		(start 291.984176 -311.383172)
		(end 291.561774 -311.805574)
		(width 0.20066)
		(layer "F.Cu")
		(net "M_B_CPU0_SA_DQS_DN<5>")
	)
	(segment
		(start 297.899582 -312.066686)
		(end 297.409108 -312.066686)
		(width 0.20066)
		(layer "F.Cu")
		(net "M_B_CPU0_SA_DQS_DN<5>")
	)
	(segment
		(start 302.076612 -311.67578)
		(end 301.843186 -311.442354)
		(width 0.18288)
		(layer "In2.Cu")
		(net "M_B_CPU0_SA_DQS_DN<5>")
	)
	(segment
		(start 327.128632 -288.336228)
		(end 327.128124 -288.336736)
		(width 0.18288)
		(layer "In2.Cu")
		(net "M_B_CPU0_SA_DQS_DN<5>")
	)
	(segment
		(start 325.620888 -292.30066)
		(end 325.458074 -292.36797)
		(width 0.18288)
		(layer "In2.Cu")
		(net "M_B_CPU0_SA_DQS_DN<5>")
	)
	(segment
		(start 309.664862 -311.70372)
		(end 309.648606 -311.70372)
		(width 0.16002)
		(layer "In2.Cu")
		(net "M_B_CPU0_SA_DQS_DN<5>")
	)
	(segment
		(start 304.490882 -312.677048)
		(end 304.462688 -312.648854)
		(width 0.16002)
		(layer "In2.Cu")
		(net "M_B_CPU0_SA_DQS_DN<5>")
	)
	(segment
		(start 306.424076 -312.633106)
		(end 306.424076 -312.648854)
		(width 0.16002)
		(layer "In2.Cu")
		(net "M_B_CPU0_SA_DQS_DN<5>")
	)
	(segment
		(start 334.599534 -276.220174)
		(end 334.600804 -276.220936)
		(width 0.088646)
		(layer "In2.Cu")
		(net "M_B_CPU0_SA_DQS_DN<5>")
	)
	(segment
		(start 334.59801 -277.847044)
		(end 334.600804 -277.848568)
		(width 0.088646)
		(layer "In2.Cu")
		(net "M_B_CPU0_SA_DQS_DN<5>")
	)
	(segment
		(start 306.66817 -312.40476)
		(end 306.639976 -312.432954)
		(width 0.16002)
		(layer "In2.Cu")
		(net "M_B_CPU0_SA_DQS_DN<5>")
	)
	(segment
		(start 300.404022 -311.881774)
		(end 300.375828 -311.909968)
		(width 0.16002)
		(layer "In2.Cu")
		(net "M_B_CPU0_SA_DQS_DN<5>")
	)
	(segment
		(start 312.00979 -311.05348)
		(end 312.00979 -311.069736)
		(width 0.16002)
		(layer "In2.Cu")
		(net "M_B_CPU0_SA_DQS_DN<5>")
	)
	(segment
		(start 306.624228 -312.432954)
		(end 306.424076 -312.633106)
		(width 0.16002)
		(layer "In2.Cu")
		(net "M_B_CPU0_SA_DQS_DN<5>")
	)
	(segment
		(start 309.8927 -311.947814)
		(end 309.864506 -311.91962)
		(width 0.16002)
		(layer "In2.Cu")
		(net "M_B_CPU0_SA_DQS_DN<5>")
	)
	(segment
		(start 302.104806 -311.703974)
		(end 302.076612 -311.67578)
		(width 0.16002)
		(layer "In2.Cu")
		(net "M_B_CPU0_SA_DQS_DN<5>")
	)
	(segment
		(start 304.029364 -312.21553)
		(end 302.616362 -312.21553)
		(width 0.18288)
		(layer "In2.Cu")
		(net "M_B_CPU0_SA_DQS_DN<5>")
	)
	(segment
		(start 312.253884 -310.825642)
		(end 312.22569 -310.853836)
		(width 0.16002)
		(layer "In2.Cu")
		(net "M_B_CPU0_SA_DQS_DN<5>")
	)
	(segment
		(start 302.320706 -311.903618)
		(end 302.121062 -311.703974)
		(width 0.16002)
		(layer "In2.Cu")
		(net "M_B_CPU0_SA_DQS_DN<5>")
	)
	(segment
		(start 304.262536 -312.432954)
		(end 304.246788 -312.432954)
		(width 0.16002)
		(layer "In2.Cu")
		(net "M_B_CPU0_SA_DQS_DN<5>")
	)
	(segment
		(start 306.198524 -312.874406)
		(end 304.68824 -312.874406)
		(width 0.18288)
		(layer "In2.Cu")
		(net "M_B_CPU0_SA_DQS_DN<5>")
	)
	(segment
		(start 334.59801 -275.570442)
		(end 334.58912 -275.575522)
		(width 0.088646)
		(layer "In2.Cu")
		(net "M_B_CPU0_SA_DQS_DN<5>")
	)
	(segment
		(start 338.387436 -275.08073)
		(end 338.44484 -275.023326)
		(width 0.088646)
		(layer "In2.Cu")
		(net "M_B_CPU0_SA_DQS_DN<5>")
	)
	(segment
		(start 309.864506 -311.903364)
		(end 309.664862 -311.70372)
		(width 0.16002)
		(layer "In2.Cu")
		(net "M_B_CPU0_SA_DQS_DN<5>")
	)
	(segment
		(start 333.774034 -278.901652)
		(end 333.394812 -279.280874)
		(width 0.088646)
		(layer "In2.Cu")
		(net "M_B_CPU0_SA_DQS_DN<5>")
	)
	(segment
		(start 330.616306 -283.854906)
		(end 329.913742 -285.550864)
		(width 0.18288)
		(layer "In2.Cu")
		(net "M_B_CPU0_SA_DQS_DN<5>")
	)
	(segment
		(start 306.395882 -312.677048)
		(end 306.198524 -312.874406)
		(width 0.18288)
		(layer "In2.Cu")
		(net "M_B_CPU0_SA_DQS_DN<5>")
	)
	(segment
		(start 300.619922 -311.665874)
		(end 300.603666 -311.665874)
		(width 0.16002)
		(layer "In2.Cu")
		(net "M_B_CPU0_SA_DQS_DN<5>")
	)
	(segment
		(start 308.153816 -311.675526)
		(end 308.125622 -311.70372)
		(width 0.16002)
		(layer "In2.Cu")
		(net "M_B_CPU0_SA_DQS_DN<5>")
	)
	(segment
		(start 334.59801 -277.198328)
		(end 334.58912 -277.203408)
		(width 0.088646)
		(layer "In2.Cu")
		(net "M_B_CPU0_SA_DQS_DN<5>")
	)
	(segment
		(start 325.97344 -291.124132)
		(end 325.763636 -291.630862)
		(width 0.18288)
		(layer "In2.Cu")
		(net "M_B_CPU0_SA_DQS_DN<5>")
	)
	(segment
		(start 300.843442 -311.442354)
		(end 300.648116 -311.63768)
		(width 0.18288)
		(layer "In2.Cu")
		(net "M_B_CPU0_SA_DQS_DN<5>")
	)
	(segment
		(start 308.109366 -311.70372)
		(end 307.909722 -311.903364)
		(width 0.16002)
		(layer "In2.Cu")
		(net "M_B_CPU0_SA_DQS_DN<5>")
	)
	(segment
		(start 322.667884 -299.10405)
		(end 322.103242 -301.942754)
		(width 0.18288)
		(layer "In2.Cu")
		(net "M_B_CPU0_SA_DQS_DN<5>")
	)
	(segment
		(start 333.394812 -279.280874)
		(end 332.96987 -279.280874)
		(width 0.088646)
		(layer "In2.Cu")
		(net "M_B_CPU0_SA_DQS_DN<5>")
	)
	(segment
		(start 304.462688 -312.633106)
		(end 304.262536 -312.432954)
		(width 0.16002)
		(layer "In2.Cu")
		(net "M_B_CPU0_SA_DQS_DN<5>")
	)
	(segment
		(start 312.00979 -311.069736)
		(end 311.981596 -311.09793)
		(width 0.16002)
		(layer "In2.Cu")
		(net "M_B_CPU0_SA_DQS_DN<5>")
	)
	(segment
		(start 310.101996 -312.15711)
		(end 309.8927 -311.947814)
		(width 0.18288)
		(layer "In2.Cu")
		(net "M_B_CPU0_SA_DQS_DN<5>")
	)
	(segment
		(start 310.922416 -312.15711)
		(end 310.101996 -312.15711)
		(width 0.18288)
		(layer "In2.Cu")
		(net "M_B_CPU0_SA_DQS_DN<5>")
	)
	(segment
		(start 304.218594 -312.40476)
		(end 304.029364 -312.21553)
		(width 0.18288)
		(layer "In2.Cu")
		(net "M_B_CPU0_SA_DQS_DN<5>")
	)
	(segment
		(start 306.87518 -312.19775)
		(end 306.66817 -312.40476)
		(width 0.18288)
		(layer "In2.Cu")
		(net "M_B_CPU0_SA_DQS_DN<5>")
	)
	(segment
		(start 299.306234 -311.790334)
		(end 299.029882 -312.066686)
		(width 0.18288)
		(layer "In2.Cu")
		(net "M_B_CPU0_SA_DQS_DN<5>")
	)
	(segment
		(start 334.315562 -278.901652)
		(end 333.774034 -278.901652)
		(width 0.088646)
		(layer "In2.Cu")
		(net "M_B_CPU0_SA_DQS_DN<5>")
	)
	(segment
		(start 301.843186 -311.442354)
		(end 300.843442 -311.442354)
		(width 0.18288)
		(layer "In2.Cu")
		(net "M_B_CPU0_SA_DQS_DN<5>")
	)
	(segment
		(start 326.346312 -290.549584)
		(end 326.136254 -291.056568)
		(width 0.18288)
		(layer "In2.Cu")
		(net "M_B_CPU0_SA_DQS_DN<5>")
	)
	(segment
		(start 306.424076 -312.648854)
		(end 306.395882 -312.677048)
		(width 0.16002)
		(layer "In2.Cu")
		(net "M_B_CPU0_SA_DQS_DN<5>")
	)
	(segment
		(start 304.68824 -312.874406)
		(end 304.490882 -312.677048)
		(width 0.18288)
		(layer "In2.Cu")
		(net "M_B_CPU0_SA_DQS_DN<5>")
	)
	(segment
		(start 334.880712 -276.708616)
		(end 334.880712 -276.72284)
		(width 0.088646)
		(layer "In2.Cu")
		(net "M_B_CPU0_SA_DQS_DN<5>")
	)
	(segment
		(start 307.909722 -311.903364)
		(end 307.909722 -311.91962)
		(width 0.16002)
		(layer "In2.Cu")
		(net "M_B_CPU0_SA_DQS_DN<5>")
	)
	(segment
		(start 332.96987 -279.280874)
		(end 332.80858 -279.442164)
		(width 0.088646)
		(layer "In2.Cu")
		(net "M_B_CPU0_SA_DQS_DN<5>")
	)
	(segment
		(start 314.62599 -311.29732)
		(end 314.192158 -311.29732)
		(width 0.18288)
		(layer "In2.Cu")
		(net "M_B_CPU0_SA_DQS_DN<5>")
	)
	(segment
		(start 302.3489 -311.948068)
		(end 302.320706 -311.919874)
		(width 0.16002)
		(layer "In2.Cu")
		(net "M_B_CPU0_SA_DQS_DN<5>")
	)
	(segment
		(start 309.513732 -311.568846)
		(end 308.260496 -311.568846)
		(width 0.18288)
		(layer "In2.Cu")
		(net "M_B_CPU0_SA_DQS_DN<5>")
	)
	(segment
		(start 329.913742 -285.550864)
		(end 327.128632 -288.336228)
		(width 0.18288)
		(layer "In2.Cu")
		(net "M_B_CPU0_SA_DQS_DN<5>")
	)
	(segment
		(start 326.279002 -290.387024)
		(end 326.346312 -290.549584)
		(width 0.18288)
		(layer "In2.Cu")
		(net "M_B_CPU0_SA_DQS_DN<5>")
	)
	(segment
		(start 309.620412 -311.675526)
		(end 309.513732 -311.568846)
		(width 0.18288)
		(layer "In2.Cu")
		(net "M_B_CPU0_SA_DQS_DN<5>")
	)
	(segment
		(start 309.864506 -311.91962)
		(end 309.864506 -311.903364)
		(width 0.16002)
		(layer "In2.Cu")
		(net "M_B_CPU0_SA_DQS_DN<5>")
	)
	(segment
		(start 334.58912 -276.214078)
		(end 334.597248 -276.21865)
		(width 0.088646)
		(layer "In2.Cu")
		(net "M_B_CPU0_SA_DQS_DN<5>")
	)
	(segment
		(start 313.992768 -311.09793)
		(end 313.964574 -311.069736)
		(width 0.16002)
		(layer "In2.Cu")
		(net "M_B_CPU0_SA_DQS_DN<5>")
	)
	(segment
		(start 312.22569 -310.853836)
		(end 312.209434 -310.853836)
		(width 0.16002)
		(layer "In2.Cu")
		(net "M_B_CPU0_SA_DQS_DN<5>")
	)
	(segment
		(start 313.72048 -310.825642)
		(end 313.6138 -310.718962)
		(width 0.18288)
		(layer "In2.Cu")
		(net "M_B_CPU0_SA_DQS_DN<5>")
	)
	(segment
		(start 300.375828 -311.909968)
		(end 300.249336 -312.03646)
		(width 0.18288)
		(layer "In2.Cu")
		(net "M_B_CPU0_SA_DQS_DN<5>")
	)
	(segment
		(start 327.128124 -288.336736)
		(end 326.279002 -290.387024)
		(width 0.18288)
		(layer "In2.Cu")
		(net "M_B_CPU0_SA_DQS_DN<5>")
	)
	(segment
		(start 307.631592 -312.19775)
		(end 306.87518 -312.19775)
		(width 0.18288)
		(layer "In2.Cu")
		(net "M_B_CPU0_SA_DQS_DN<5>")
	)
	(segment
		(start 320.627756 -305.505358)
		(end 314.983622 -311.148984)
		(width 0.18288)
		(layer "In2.Cu")
		(net "M_B_CPU0_SA_DQS_DN<5>")
	)
	(segment
		(start 325.458074 -292.36797)
		(end 322.667884 -299.10405)
		(width 0.18288)
		(layer "In2.Cu")
		(net "M_B_CPU0_SA_DQS_DN<5>")
	)
	(segment
		(start 299.70984 -312.03646)
		(end 299.463714 -311.790334)
		(width 0.18288)
		(layer "In2.Cu")
		(net "M_B_CPU0_SA_DQS_DN<5>")
	)
	(segment
		(start 334.597248 -276.21865)
		(end 334.599534 -276.220174)
		(width 0.088646)
		(layer "In2.Cu")
		(net "M_B_CPU0_SA_DQS_DN<5>")
	)
	(segment
		(start 302.616362 -312.21553)
		(end 302.3489 -311.948068)
		(width 0.18288)
		(layer "In2.Cu")
		(net "M_B_CPU0_SA_DQS_DN<5>")
	)
	(segment
		(start 330.799186 -283.413454)
		(end 330.616306 -283.854906)
		(width 0.18288)
		(layer "In2.Cu")
		(net "M_B_CPU0_SA_DQS_DN<5>")
	)
	(segment
		(start 334.596486 -277.846282)
		(end 334.59801 -277.847044)
		(width 0.088646)
		(layer "In2.Cu")
		(net "M_B_CPU0_SA_DQS_DN<5>")
	)
	(segment
		(start 326.136254 -291.056568)
		(end 325.97344 -291.124132)
		(width 0.18288)
		(layer "In2.Cu")
		(net "M_B_CPU0_SA_DQS_DN<5>")
	)
	(segment
		(start 325.830946 -291.793422)
		(end 325.620888 -292.30066)
		(width 0.18288)
		(layer "In2.Cu")
		(net "M_B_CPU0_SA_DQS_DN<5>")
	)
	(segment
		(start 302.320706 -311.919874)
		(end 302.320706 -311.903618)
		(width 0.16002)
		(layer "In2.Cu")
		(net "M_B_CPU0_SA_DQS_DN<5>")
	)
	(segment
		(start 334.58912 -277.841964)
		(end 334.596486 -277.846282)
		(width 0.088646)
		(layer "In2.Cu")
		(net "M_B_CPU0_SA_DQS_DN<5>")
	)
	(segment
		(start 334.880204 -275.07565)
		(end 334.880204 -275.09978)
		(width 0.088646)
		(layer "In2.Cu")
		(net "M_B_CPU0_SA_DQS_DN<5>")
	)
	(segment
		(start 322.103242 -301.942754)
		(end 320.627756 -305.505358)
		(width 0.18288)
		(layer "In2.Cu")
		(net "M_B_CPU0_SA_DQS_DN<5>")
	)
	(segment
		(start 312.360564 -310.718962)
		(end 312.253884 -310.825642)
		(width 0.18288)
		(layer "In2.Cu")
		(net "M_B_CPU0_SA_DQS_DN<5>")
	)
	(segment
		(start 336.007964 -274.756372)
		(end 335.99755 -274.762468)
		(width 0.088646)
		(layer "In2.Cu")
		(net "M_B_CPU0_SA_DQS_DN<5>")
	)
	(segment
		(start 314.192158 -311.29732)
		(end 313.992768 -311.09793)
		(width 0.18288)
		(layer "In2.Cu")
		(net "M_B_CPU0_SA_DQS_DN<5>")
	)
	(segment
		(start 300.648116 -311.63768)
		(end 300.619922 -311.665874)
		(width 0.16002)
		(layer "In2.Cu")
		(net "M_B_CPU0_SA_DQS_DN<5>")
	)
	(segment
		(start 302.121062 -311.703974)
		(end 302.104806 -311.703974)
		(width 0.16002)
		(layer "In2.Cu")
		(net "M_B_CPU0_SA_DQS_DN<5>")
	)
	(segment
		(start 309.648606 -311.70372)
		(end 309.620412 -311.675526)
		(width 0.16002)
		(layer "In2.Cu")
		(net "M_B_CPU0_SA_DQS_DN<5>")
	)
	(segment
		(start 325.763636 -291.630862)
		(end 325.830946 -291.793422)
		(width 0.18288)
		(layer "In2.Cu")
		(net "M_B_CPU0_SA_DQS_DN<5>")
	)
	(segment
		(start 332.80858 -279.442164)
		(end 332.80858 -279.527)
		(width 0.088646)
		(layer "In2.Cu")
		(net "M_B_CPU0_SA_DQS_DN<5>")
	)
	(segment
		(start 306.639976 -312.432954)
		(end 306.624228 -312.432954)
		(width 0.16002)
		(layer "In2.Cu")
		(net "M_B_CPU0_SA_DQS_DN<5>")
	)
	(segment
		(start 300.404022 -311.865518)
		(end 300.404022 -311.881774)
		(width 0.16002)
		(layer "In2.Cu")
		(net "M_B_CPU0_SA_DQS_DN<5>")
	)
	(segment
		(start 338.074762 -275.08073)
		(end 338.387436 -275.08073)
		(width 0.088646)
		(layer "In2.Cu")
		(net "M_B_CPU0_SA_DQS_DN<5>")
	)
	(segment
		(start 313.748674 -310.853836)
		(end 313.72048 -310.825642)
		(width 0.16002)
		(layer "In2.Cu")
		(net "M_B_CPU0_SA_DQS_DN<5>")
	)
	(segment
		(start 304.462688 -312.648854)
		(end 304.462688 -312.633106)
		(width 0.16002)
		(layer "In2.Cu")
		(net "M_B_CPU0_SA_DQS_DN<5>")
	)
	(segment
		(start 307.909722 -311.91962)
		(end 307.881528 -311.947814)
		(width 0.16002)
		(layer "In2.Cu")
		(net "M_B_CPU0_SA_DQS_DN<5>")
	)
	(segment
		(start 308.125622 -311.70372)
		(end 308.109366 -311.70372)
		(width 0.16002)
		(layer "In2.Cu")
		(net "M_B_CPU0_SA_DQS_DN<5>")
	)
	(segment
		(start 314.983622 -311.148984)
		(end 314.62599 -311.29732)
		(width 0.18288)
		(layer "In2.Cu")
		(net "M_B_CPU0_SA_DQS_DN<5>")
	)
	(segment
		(start 334.600804 -276.220936)
		(end 334.604106 -276.222714)
		(width 0.088646)
		(layer "In2.Cu")
		(net "M_B_CPU0_SA_DQS_DN<5>")
	)
	(segment
		(start 313.76493 -310.853836)
		(end 313.748674 -310.853836)
		(width 0.16002)
		(layer "In2.Cu")
		(net "M_B_CPU0_SA_DQS_DN<5>")
	)
	(segment
		(start 311.981596 -311.09793)
		(end 310.922416 -312.15711)
		(width 0.18288)
		(layer "In2.Cu")
		(net "M_B_CPU0_SA_DQS_DN<5>")
	)
	(segment
		(start 312.209434 -310.853836)
		(end 312.00979 -311.05348)
		(width 0.16002)
		(layer "In2.Cu")
		(net "M_B_CPU0_SA_DQS_DN<5>")
	)
	(segment
		(start 308.260496 -311.568846)
		(end 308.153816 -311.675526)
		(width 0.18288)
		(layer "In2.Cu")
		(net "M_B_CPU0_SA_DQS_DN<5>")
	)
	(segment
		(start 332.80858 -279.527)
		(end 330.799186 -281.536394)
		(width 0.18288)
		(layer "In2.Cu")
		(net "M_B_CPU0_SA_DQS_DN<5>")
	)
	(segment
		(start 330.799186 -281.536394)
		(end 330.799186 -283.413454)
		(width 0.18288)
		(layer "In2.Cu")
		(net "M_B_CPU0_SA_DQS_DN<5>")
	)
	(segment
		(start 304.246788 -312.432954)
		(end 304.218594 -312.40476)
		(width 0.16002)
		(layer "In2.Cu")
		(net "M_B_CPU0_SA_DQS_DN<5>")
	)
	(segment
		(start 300.249336 -312.03646)
		(end 299.70984 -312.03646)
		(width 0.18288)
		(layer "In2.Cu")
		(net "M_B_CPU0_SA_DQS_DN<5>")
	)
	(segment
		(start 313.964574 -311.069736)
		(end 313.964574 -311.05348)
		(width 0.16002)
		(layer "In2.Cu")
		(net "M_B_CPU0_SA_DQS_DN<5>")
	)
	(segment
		(start 307.881528 -311.947814)
		(end 307.631592 -312.19775)
		(width 0.18288)
		(layer "In2.Cu")
		(net "M_B_CPU0_SA_DQS_DN<5>")
	)
	(segment
		(start 313.6138 -310.718962)
		(end 312.360564 -310.718962)
		(width 0.18288)
		(layer "In2.Cu")
		(net "M_B_CPU0_SA_DQS_DN<5>")
	)
	(segment
		(start 334.880204 -275.09978)
		(end 334.880458 -275.099272)
		(width 0.088646)
		(layer "In2.Cu")
		(net "M_B_CPU0_SA_DQS_DN<5>")
	)
	(segment
		(start 334.600804 -277.848568)
		(end 334.604106 -277.8506)
		(width 0.088646)
		(layer "In2.Cu")
		(net "M_B_CPU0_SA_DQS_DN<5>")
	)
	(segment
		(start 313.964574 -311.05348)
		(end 313.76493 -310.853836)
		(width 0.16002)
		(layer "In2.Cu")
		(net "M_B_CPU0_SA_DQS_DN<5>")
	)
	(segment
		(start 300.603666 -311.665874)
		(end 300.404022 -311.865518)
		(width 0.16002)
		(layer "In2.Cu")
		(net "M_B_CPU0_SA_DQS_DN<5>")
	)
	(segment
		(start 299.463714 -311.790334)
		(end 299.306234 -311.790334)
		(width 0.18288)
		(layer "In2.Cu")
		(net "M_B_CPU0_SA_DQS_DN<5>")
	)
	(arc
		(start 335.06791 -274.756372)
		(mid 334.931797 -274.891185)
		(end 334.880204 -275.07565)
		(width 0.088646)
		(layer "In2.Cu")
		(net "M_B_CPU0_SA_DQS_DN<5>")
	)
	(arc
		(start 335.442306 -274.756372)
		(mid 335.255108 -274.706229)
		(end 335.06791 -274.756372)
		(width 0.088646)
		(layer "In2.Cu")
		(net "M_B_CPU0_SA_DQS_DN<5>")
	)
	(arc
		(start 337.32216 -274.756372)
		(mid 337.134962 -274.706229)
		(end 336.947764 -274.756372)
		(width 0.088646)
		(layer "In2.Cu")
		(net "M_B_CPU0_SA_DQS_DN<5>")
	)
	(arc
		(start 336.38236 -274.756372)
		(mid 336.195162 -274.706229)
		(end 336.007964 -274.756372)
		(width 0.088646)
		(layer "In2.Cu")
		(net "M_B_CPU0_SA_DQS_DN<5>")
	)
	(arc
		(start 334.58912 -275.575522)
		(mid 334.410644 -275.8948)
		(end 334.58912 -276.214078)
		(width 0.088646)
		(layer "In2.Cu")
		(net "M_B_CPU0_SA_DQS_DN<5>")
	)
	(arc
		(start 334.604106 -277.8506)
		(mid 334.860641 -278.486095)
		(end 334.315562 -278.901652)
		(width 0.088646)
		(layer "In2.Cu")
		(net "M_B_CPU0_SA_DQS_DN<5>")
	)
	(arc
		(start 334.880458 -275.099272)
		(mid 334.800296 -275.371461)
		(end 334.59801 -275.570442)
		(width 0.088646)
		(layer "In2.Cu")
		(net "M_B_CPU0_SA_DQS_DN<5>")
	)
	(arc
		(start 336.947764 -274.756372)
		(mid 336.665062 -274.832148)
		(end 336.38236 -274.756372)
		(width 0.088646)
		(layer "In2.Cu")
		(net "M_B_CPU0_SA_DQS_DN<5>")
	)
	(arc
		(start 337.887564 -274.756372)
		(mid 337.604862 -274.832148)
		(end 337.32216 -274.756372)
		(width 0.088646)
		(layer "In2.Cu")
		(net "M_B_CPU0_SA_DQS_DN<5>")
	)
	(arc
		(start 334.604106 -276.222714)
		(mid 334.806693 -276.429065)
		(end 334.880712 -276.708616)
		(width 0.088646)
		(layer "In2.Cu")
		(net "M_B_CPU0_SA_DQS_DN<5>")
	)
	(arc
		(start 334.880712 -276.72284)
		(mid 334.801493 -276.997525)
		(end 334.59801 -277.198328)
		(width 0.088646)
		(layer "In2.Cu")
		(net "M_B_CPU0_SA_DQS_DN<5>")
	)
	(arc
		(start 338.44484 -275.023326)
		(mid 338.236557 -274.74298)
		(end 337.887564 -274.756372)
		(width 0.088646)
		(layer "In2.Cu")
		(net "M_B_CPU0_SA_DQS_DN<5>")
	)
	(arc
		(start 334.58912 -277.203408)
		(mid 334.410402 -277.522686)
		(end 334.58912 -277.841964)
		(width 0.088646)
		(layer "In2.Cu")
		(net "M_B_CPU0_SA_DQS_DN<5>")
	)
	(arc
		(start 335.99755 -274.762468)
		(mid 335.719118 -274.832314)
		(end 335.442306 -274.756372)
		(width 0.088646)
		(layer "In2.Cu")
		(net "M_B_CPU0_SA_DQS_DN<5>")
	)
	(segment
		(start 286.804354 -274.66671)
		(end 286.255714 -274.66671)
		(width 0.20066)
		(layer "F.Cu")
		(net "M_B_CPU0_SA_DQS_DN<4>")
	)
	(segment
		(start 289.243008 -275.091652)
		(end 289.23234 -275.080984)
		(width 0.101854)
		(layer "F.Cu")
		(net "M_B_CPU0_SA_DQS_DN<4>")
	)
	(segment
		(start 336.195162 -259.894832)
		(end 336.195162 -260.430772)
		(width 0.20066)
		(layer "F.Cu")
		(net "M_B_CPU0_SA_DQS_DN<4>")
	)
	(segment
		(start 294.904414 -274.66671)
		(end 293.799514 -274.66671)
		(width 0.20066)
		(layer "F.Cu")
		(net "M_B_CPU0_SA_DQS_DN<4>")
	)
	(segment
		(start 293.799514 -274.66671)
		(end 293.252906 -274.66671)
		(width 0.20066)
		(layer "F.Cu")
		(net "M_B_CPU0_SA_DQS_DN<4>")
	)
	(segment
		(start 287.579308 -274.927822)
		(end 287.065466 -274.927822)
		(width 0.20066)
		(layer "F.Cu")
		(net "M_B_CPU0_SA_DQS_DN<4>")
	)
	(segment
		(start 289.23234 -275.080984)
		(end 289.231578 -275.080984)
		(width 0.101854)
		(layer "F.Cu")
		(net "M_B_CPU0_SA_DQS_DN<4>")
	)
	(segment
		(start 288.215324 -275.353018)
		(end 287.579308 -274.927822)
		(width 0.20066)
		(layer "F.Cu")
		(net "M_B_CPU0_SA_DQS_DN<4>")
	)
	(segment
		(start 292.58514 -274.927822)
		(end 292.159944 -275.353018)
		(width 0.20066)
		(layer "F.Cu")
		(net "M_B_CPU0_SA_DQS_DN<4>")
	)
	(segment
		(start 288.755328 -275.353018)
		(end 288.215324 -275.353018)
		(width 0.20066)
		(layer "F.Cu")
		(net "M_B_CPU0_SA_DQS_DN<4>")
	)
	(segment
		(start 292.991794 -274.927822)
		(end 292.58514 -274.927822)
		(width 0.20066)
		(layer "F.Cu")
		(net "M_B_CPU0_SA_DQS_DN<4>")
	)
	(segment
		(start 291.711888 -275.091652)
		(end 291.556694 -275.091652)
		(width 0.20066)
		(layer "F.Cu")
		(net "M_B_CPU0_SA_DQS_DN<4>")
	)
	(segment
		(start 287.065466 -274.927822)
		(end 286.804354 -274.66671)
		(width 0.20066)
		(layer "F.Cu")
		(net "M_B_CPU0_SA_DQS_DN<4>")
	)
	(segment
		(start 289.027362 -275.080984)
		(end 288.755328 -275.353018)
		(width 0.20066)
		(layer "F.Cu")
		(net "M_B_CPU0_SA_DQS_DN<4>")
	)
	(segment
		(start 289.231578 -275.080984)
		(end 289.027362 -275.080984)
		(width 0.20066)
		(layer "F.Cu")
		(net "M_B_CPU0_SA_DQS_DN<4>")
	)
	(segment
		(start 291.973254 -275.353018)
		(end 291.711888 -275.091652)
		(width 0.20066)
		(layer "F.Cu")
		(net "M_B_CPU0_SA_DQS_DN<4>")
	)
	(segment
		(start 291.556694 -275.091652)
		(end 289.243008 -275.091652)
		(width 0.1016)
		(layer "F.Cu")
		(net "M_B_CPU0_SA_DQS_DN<4>")
	)
	(segment
		(start 292.159944 -275.353018)
		(end 291.973254 -275.353018)
		(width 0.20066)
		(layer "F.Cu")
		(net "M_B_CPU0_SA_DQS_DN<4>")
	)
	(segment
		(start 293.252906 -274.66671)
		(end 292.991794 -274.927822)
		(width 0.20066)
		(layer "F.Cu")
		(net "M_B_CPU0_SA_DQS_DN<4>")
	)
	(segment
		(start 302.097186 -275.876766)
		(end 302.068992 -275.90496)
		(width 0.16002)
		(layer "In2.Cu")
		(net "M_B_CPU0_SA_DQS_DN<4>")
	)
	(segment
		(start 314.168028 -273.43735)
		(end 314.08243 -273.351752)
		(width 0.18288)
		(layer "In2.Cu")
		(net "M_B_CPU0_SA_DQS_DN<4>")
	)
	(segment
		(start 302.313086 -275.660866)
		(end 302.313086 -275.677122)
		(width 0.16002)
		(layer "In2.Cu")
		(net "M_B_CPU0_SA_DQS_DN<4>")
	)
	(segment
		(start 319.75933 -268.136878)
		(end 319.371472 -268.524736)
		(width 0.18288)
		(layer "In2.Cu")
		(net "M_B_CPU0_SA_DQS_DN<4>")
	)
	(segment
		(start 300.345348 -275.632672)
		(end 300.061884 -275.349208)
		(width 0.18288)
		(layer "In2.Cu")
		(net "M_B_CPU0_SA_DQS_DN<4>")
	)
	(segment
		(start 325.478394 -264.09523)
		(end 322.615306 -265.280902)
		(width 0.18288)
		(layer "In2.Cu")
		(net "M_B_CPU0_SA_DQS_DN<4>")
	)
	(segment
		(start 320.323464 -267.572744)
		(end 320.147442 -267.572744)
		(width 0.18288)
		(layer "In2.Cu")
		(net "M_B_CPU0_SA_DQS_DN<4>")
	)
	(segment
		(start 314.08243 -273.351752)
		(end 314.054236 -273.323558)
		(width 0.16002)
		(layer "In2.Cu")
		(net "M_B_CPU0_SA_DQS_DN<4>")
	)
	(segment
		(start 304.569876 -274.907248)
		(end 304.380138 -274.71751)
		(width 0.18288)
		(layer "In2.Cu")
		(net "M_B_CPU0_SA_DQS_DN<4>")
	)
	(segment
		(start 312.077608 -273.122136)
		(end 312.049414 -273.15033)
		(width 0.16002)
		(layer "In2.Cu")
		(net "M_B_CPU0_SA_DQS_DN<4>")
	)
	(segment
		(start 312.049414 -273.166078)
		(end 311.851802 -273.36369)
		(width 0.16002)
		(layer "In2.Cu")
		(net "M_B_CPU0_SA_DQS_DN<4>")
	)
	(segment
		(start 316.515496 -271.380712)
		(end 316.339474 -271.380712)
		(width 0.18288)
		(layer "In2.Cu")
		(net "M_B_CPU0_SA_DQS_DN<4>")
	)
	(segment
		(start 309.856886 -275.677122)
		(end 309.657242 -275.876766)
		(width 0.16002)
		(layer "In2.Cu")
		(net "M_B_CPU0_SA_DQS_DN<4>")
	)
	(segment
		(start 319.371472 -268.524736)
		(end 319.19545 -268.524736)
		(width 0.18288)
		(layer "In2.Cu")
		(net "M_B_CPU0_SA_DQS_DN<4>")
	)
	(segment
		(start 322.051426 -265.66876)
		(end 321.663314 -266.056872)
		(width 0.18288)
		(layer "In2.Cu")
		(net "M_B_CPU0_SA_DQS_DN<4>")
	)
	(segment
		(start 315.387482 -272.332704)
		(end 314.99937 -272.720816)
		(width 0.18288)
		(layer "In2.Cu")
		(net "M_B_CPU0_SA_DQS_DN<4>")
	)
	(segment
		(start 317.855346 -270.040862)
		(end 317.467488 -270.42872)
		(width 0.18288)
		(layer "In2.Cu")
		(net "M_B_CPU0_SA_DQS_DN<4>")
	)
	(segment
		(start 320.711322 -267.184886)
		(end 320.323464 -267.572744)
		(width 0.18288)
		(layer "In2.Cu")
		(net "M_B_CPU0_SA_DQS_DN<4>")
	)
	(segment
		(start 309.640986 -275.876766)
		(end 309.612792 -275.90496)
		(width 0.16002)
		(layer "In2.Cu")
		(net "M_B_CPU0_SA_DQS_DN<4>")
	)
	(segment
		(start 313.838336 -273.107658)
		(end 313.810142 -273.079464)
		(width 0.16002)
		(layer "In2.Cu")
		(net "M_B_CPU0_SA_DQS_DN<4>")
	)
	(segment
		(start 297.05427 -274.950682)
		(end 297.026076 -274.922488)
		(width 0.16002)
		(layer "In2.Cu")
		(net "M_B_CPU0_SA_DQS_DN<4>")
	)
	(segment
		(start 311.15381 -273.87042)
		(end 310.765698 -274.258786)
		(width 0.18288)
		(layer "In2.Cu")
		(net "M_B_CPU0_SA_DQS_DN<4>")
	)
	(segment
		(start 314.99937 -272.896838)
		(end 314.458858 -273.43735)
		(width 0.18288)
		(layer "In2.Cu")
		(net "M_B_CPU0_SA_DQS_DN<4>")
	)
	(segment
		(start 315.951362 -271.768824)
		(end 315.951362 -271.944846)
		(width 0.18288)
		(layer "In2.Cu")
		(net "M_B_CPU0_SA_DQS_DN<4>")
	)
	(segment
		(start 305.024282 -275.361654)
		(end 304.842164 -275.179536)
		(width 0.18288)
		(layer "In2.Cu")
		(net "M_B_CPU0_SA_DQS_DN<4>")
	)
	(segment
		(start 302.068992 -275.90496)
		(end 301.978822 -275.99513)
		(width 0.18288)
		(layer "In2.Cu")
		(net "M_B_CPU0_SA_DQS_DN<4>")
	)
	(segment
		(start 309.657242 -275.876766)
		(end 309.640986 -275.876766)
		(width 0.16002)
		(layer "In2.Cu")
		(net "M_B_CPU0_SA_DQS_DN<4>")
	)
	(segment
		(start 300.061884 -275.349208)
		(end 299.456856 -275.349208)
		(width 0.18288)
		(layer "In2.Cu")
		(net "M_B_CPU0_SA_DQS_DN<4>")
	)
	(segment
		(start 313.810142 -273.079464)
		(end 313.553348 -272.82267)
		(width 0.18288)
		(layer "In2.Cu")
		(net "M_B_CPU0_SA_DQS_DN<4>")
	)
	(segment
		(start 312.049414 -273.15033)
		(end 312.049414 -273.166078)
		(width 0.16002)
		(layer "In2.Cu")
		(net "M_B_CPU0_SA_DQS_DN<4>")
	)
	(segment
		(start 335.068164 -260.755384)
		(end 335.068164 -260.75513)
		(width 0.088646)
		(layer "In2.Cu")
		(net "M_B_CPU0_SA_DQS_DN<4>")
	)
	(segment
		(start 307.889148 -275.632672)
		(end 307.61813 -275.361654)
		(width 0.18288)
		(layer "In2.Cu")
		(net "M_B_CPU0_SA_DQS_DN<4>")
	)
	(segment
		(start 301.978822 -275.99513)
		(end 300.707806 -275.99513)
		(width 0.18288)
		(layer "In2.Cu")
		(net "M_B_CPU0_SA_DQS_DN<4>")
	)
	(segment
		(start 312.377074 -272.82267)
		(end 312.077608 -273.122136)
		(width 0.18288)
		(layer "In2.Cu")
		(net "M_B_CPU0_SA_DQS_DN<4>")
	)
	(segment
		(start 295.98493 -274.65655)
		(end 295.65727 -274.98421)
		(width 0.18288)
		(layer "In2.Cu")
		(net "M_B_CPU0_SA_DQS_DN<4>")
	)
	(segment
		(start 319.19545 -268.524736)
		(end 318.807338 -268.912848)
		(width 0.18288)
		(layer "In2.Cu")
		(net "M_B_CPU0_SA_DQS_DN<4>")
	)
	(segment
		(start 321.663314 -266.232894)
		(end 321.275456 -266.620752)
		(width 0.18288)
		(layer "In2.Cu")
		(net "M_B_CPU0_SA_DQS_DN<4>")
	)
	(segment
		(start 316.903354 -270.992854)
		(end 316.515496 -271.380712)
		(width 0.18288)
		(layer "In2.Cu")
		(net "M_B_CPU0_SA_DQS_DN<4>")
	)
	(segment
		(start 297.27017 -275.166582)
		(end 297.253914 -275.166582)
		(width 0.16002)
		(layer "In2.Cu")
		(net "M_B_CPU0_SA_DQS_DN<4>")
	)
	(segment
		(start 297.026076 -274.922488)
		(end 296.760138 -274.65655)
		(width 0.18288)
		(layer "In2.Cu")
		(net "M_B_CPU0_SA_DQS_DN<4>")
	)
	(segment
		(start 322.615306 -265.280902)
		(end 322.227448 -265.66876)
		(width 0.18288)
		(layer "In2.Cu")
		(net "M_B_CPU0_SA_DQS_DN<4>")
	)
	(segment
		(start 331.571092 -260.679438)
		(end 329.710796 -262.53948)
		(width 0.088646)
		(layer "In2.Cu")
		(net "M_B_CPU0_SA_DQS_DN<4>")
	)
	(segment
		(start 307.917342 -275.677122)
		(end 307.917342 -275.660866)
		(width 0.16002)
		(layer "In2.Cu")
		(net "M_B_CPU0_SA_DQS_DN<4>")
	)
	(segment
		(start 317.855346 -269.86484)
		(end 317.855346 -270.040862)
		(width 0.18288)
		(layer "In2.Cu")
		(net "M_B_CPU0_SA_DQS_DN<4>")
	)
	(segment
		(start 331.966062 -260.679438)
		(end 331.571092 -260.679438)
		(width 0.088646)
		(layer "In2.Cu")
		(net "M_B_CPU0_SA_DQS_DN<4>")
	)
	(segment
		(start 308.133242 -275.876766)
		(end 308.116986 -275.876766)
		(width 0.16002)
		(layer "In2.Cu")
		(net "M_B_CPU0_SA_DQS_DN<4>")
	)
	(segment
		(start 307.61813 -275.361654)
		(end 306.996846 -275.361654)
		(width 0.18288)
		(layer "In2.Cu")
		(net "M_B_CPU0_SA_DQS_DN<4>")
	)
	(segment
		(start 311.836054 -273.36369)
		(end 311.80786 -273.391884)
		(width 0.16002)
		(layer "In2.Cu")
		(net "M_B_CPU0_SA_DQS_DN<4>")
	)
	(segment
		(start 306.725066 -275.089874)
		(end 306.371498 -275.089874)
		(width 0.18288)
		(layer "In2.Cu")
		(net "M_B_CPU0_SA_DQS_DN<4>")
	)
	(segment
		(start 309.856886 -275.660866)
		(end 309.856886 -275.677122)
		(width 0.16002)
		(layer "In2.Cu")
		(net "M_B_CPU0_SA_DQS_DN<4>")
	)
	(segment
		(start 336.011266 -260.614668)
		(end 335.967324 -260.614668)
		(width 0.088646)
		(layer "In2.Cu")
		(net "M_B_CPU0_SA_DQS_DN<4>")
	)
	(segment
		(start 309.612792 -275.90496)
		(end 309.49773 -276.020022)
		(width 0.18288)
		(layer "In2.Cu")
		(net "M_B_CPU0_SA_DQS_DN<4>")
	)
	(segment
		(start 303.199546 -275.347176)
		(end 302.626776 -275.347176)
		(width 0.18288)
		(layer "In2.Cu")
		(net "M_B_CPU0_SA_DQS_DN<4>")
	)
	(segment
		(start 326.869298 -262.704326)
		(end 325.478394 -264.09523)
		(width 0.18288)
		(layer "In2.Cu")
		(net "M_B_CPU0_SA_DQS_DN<4>")
	)
	(segment
		(start 298.548298 -275.353018)
		(end 297.456606 -275.353018)
		(width 0.18288)
		(layer "In2.Cu")
		(net "M_B_CPU0_SA_DQS_DN<4>")
	)
	(segment
		(start 303.829212 -274.71751)
		(end 303.199546 -275.347176)
		(width 0.18288)
		(layer "In2.Cu")
		(net "M_B_CPU0_SA_DQS_DN<4>")
	)
	(segment
		(start 322.227448 -265.66876)
		(end 322.051426 -265.66876)
		(width 0.18288)
		(layer "In2.Cu")
		(net "M_B_CPU0_SA_DQS_DN<4>")
	)
	(segment
		(start 321.099434 -266.620752)
		(end 320.711322 -267.008864)
		(width 0.18288)
		(layer "In2.Cu")
		(net "M_B_CPU0_SA_DQS_DN<4>")
	)
	(segment
		(start 310.765698 -274.434808)
		(end 310.378094 -274.822666)
		(width 0.18288)
		(layer "In2.Cu")
		(net "M_B_CPU0_SA_DQS_DN<4>")
	)
	(segment
		(start 297.05427 -274.966938)
		(end 297.05427 -274.950682)
		(width 0.16002)
		(layer "In2.Cu")
		(net "M_B_CPU0_SA_DQS_DN<4>")
	)
	(segment
		(start 314.99937 -272.720816)
		(end 314.99937 -272.896838)
		(width 0.18288)
		(layer "In2.Cu")
		(net "M_B_CPU0_SA_DQS_DN<4>")
	)
	(segment
		(start 321.663314 -266.056872)
		(end 321.663314 -266.232894)
		(width 0.18288)
		(layer "In2.Cu")
		(net "M_B_CPU0_SA_DQS_DN<4>")
	)
	(segment
		(start 309.49773 -276.020022)
		(end 308.276498 -276.020022)
		(width 0.18288)
		(layer "In2.Cu")
		(net "M_B_CPU0_SA_DQS_DN<4>")
	)
	(segment
		(start 304.842164 -275.179536)
		(end 304.81397 -275.151342)
		(width 0.16002)
		(layer "In2.Cu")
		(net "M_B_CPU0_SA_DQS_DN<4>")
	)
	(segment
		(start 306.099718 -275.361654)
		(end 305.024282 -275.361654)
		(width 0.18288)
		(layer "In2.Cu")
		(net "M_B_CPU0_SA_DQS_DN<4>")
	)
	(segment
		(start 315.951362 -271.944846)
		(end 315.563504 -272.332704)
		(width 0.18288)
		(layer "In2.Cu")
		(net "M_B_CPU0_SA_DQS_DN<4>")
	)
	(segment
		(start 295.221914 -274.98421)
		(end 294.904414 -274.66671)
		(width 0.18288)
		(layer "In2.Cu")
		(net "M_B_CPU0_SA_DQS_DN<4>")
	)
	(segment
		(start 302.113442 -275.876766)
		(end 302.097186 -275.876766)
		(width 0.16002)
		(layer "In2.Cu")
		(net "M_B_CPU0_SA_DQS_DN<4>")
	)
	(segment
		(start 329.710796 -262.53948)
		(end 329.31354 -262.704326)
		(width 0.088646)
		(layer "In2.Cu")
		(net "M_B_CPU0_SA_DQS_DN<4>")
	)
	(segment
		(start 320.147442 -267.572744)
		(end 319.75933 -267.960856)
		(width 0.18288)
		(layer "In2.Cu")
		(net "M_B_CPU0_SA_DQS_DN<4>")
	)
	(segment
		(start 300.589442 -275.876766)
		(end 300.573186 -275.876766)
		(width 0.16002)
		(layer "In2.Cu")
		(net "M_B_CPU0_SA_DQS_DN<4>")
	)
	(segment
		(start 297.253914 -275.166582)
		(end 297.05427 -274.966938)
		(width 0.16002)
		(layer "In2.Cu")
		(net "M_B_CPU0_SA_DQS_DN<4>")
	)
	(segment
		(start 300.617636 -275.90496)
		(end 300.589442 -275.876766)
		(width 0.16002)
		(layer "In2.Cu")
		(net "M_B_CPU0_SA_DQS_DN<4>")
	)
	(segment
		(start 311.80786 -273.391884)
		(end 311.329832 -273.87042)
		(width 0.18288)
		(layer "In2.Cu")
		(net "M_B_CPU0_SA_DQS_DN<4>")
	)
	(segment
		(start 304.59807 -274.935442)
		(end 304.569876 -274.907248)
		(width 0.16002)
		(layer "In2.Cu")
		(net "M_B_CPU0_SA_DQS_DN<4>")
	)
	(segment
		(start 304.59807 -274.951698)
		(end 304.59807 -274.935442)
		(width 0.16002)
		(layer "In2.Cu")
		(net "M_B_CPU0_SA_DQS_DN<4>")
	)
	(segment
		(start 308.116986 -275.876766)
		(end 307.917342 -275.677122)
		(width 0.16002)
		(layer "In2.Cu")
		(net "M_B_CPU0_SA_DQS_DN<4>")
	)
	(segment
		(start 317.291466 -270.42872)
		(end 316.903354 -270.816832)
		(width 0.18288)
		(layer "In2.Cu")
		(net "M_B_CPU0_SA_DQS_DN<4>")
	)
	(segment
		(start 321.275456 -266.620752)
		(end 321.099434 -266.620752)
		(width 0.18288)
		(layer "In2.Cu")
		(net "M_B_CPU0_SA_DQS_DN<4>")
	)
	(segment
		(start 313.838336 -273.123406)
		(end 313.838336 -273.107658)
		(width 0.16002)
		(layer "In2.Cu")
		(net "M_B_CPU0_SA_DQS_DN<4>")
	)
	(segment
		(start 300.707806 -275.99513)
		(end 300.617636 -275.90496)
		(width 0.18288)
		(layer "In2.Cu")
		(net "M_B_CPU0_SA_DQS_DN<4>")
	)
	(segment
		(start 308.276498 -276.020022)
		(end 308.161436 -275.90496)
		(width 0.18288)
		(layer "In2.Cu")
		(net "M_B_CPU0_SA_DQS_DN<4>")
	)
	(segment
		(start 310.765698 -274.258786)
		(end 310.765698 -274.434808)
		(width 0.18288)
		(layer "In2.Cu")
		(net "M_B_CPU0_SA_DQS_DN<4>")
	)
	(segment
		(start 299.1993 -275.091652)
		(end 298.809664 -275.091652)
		(width 0.18288)
		(layer "In2.Cu")
		(net "M_B_CPU0_SA_DQS_DN<4>")
	)
	(segment
		(start 298.809664 -275.091652)
		(end 298.548298 -275.353018)
		(width 0.18288)
		(layer "In2.Cu")
		(net "M_B_CPU0_SA_DQS_DN<4>")
	)
	(segment
		(start 314.458858 -273.43735)
		(end 314.168028 -273.43735)
		(width 0.18288)
		(layer "In2.Cu")
		(net "M_B_CPU0_SA_DQS_DN<4>")
	)
	(segment
		(start 316.903354 -270.816832)
		(end 316.903354 -270.992854)
		(width 0.18288)
		(layer "In2.Cu")
		(net "M_B_CPU0_SA_DQS_DN<4>")
	)
	(segment
		(start 297.456606 -275.353018)
		(end 297.298364 -275.194776)
		(width 0.18288)
		(layer "In2.Cu")
		(net "M_B_CPU0_SA_DQS_DN<4>")
	)
	(segment
		(start 320.711322 -267.008864)
		(end 320.711322 -267.184886)
		(width 0.18288)
		(layer "In2.Cu")
		(net "M_B_CPU0_SA_DQS_DN<4>")
	)
	(segment
		(start 314.054236 -273.323558)
		(end 314.038488 -273.323558)
		(width 0.16002)
		(layer "In2.Cu")
		(net "M_B_CPU0_SA_DQS_DN<4>")
	)
	(segment
		(start 318.807338 -268.912848)
		(end 318.807338 -269.08887)
		(width 0.18288)
		(layer "In2.Cu")
		(net "M_B_CPU0_SA_DQS_DN<4>")
	)
	(segment
		(start 304.797714 -275.151342)
		(end 304.59807 -274.951698)
		(width 0.16002)
		(layer "In2.Cu")
		(net "M_B_CPU0_SA_DQS_DN<4>")
	)
	(segment
		(start 318.807338 -269.08887)
		(end 318.41948 -269.476728)
		(width 0.18288)
		(layer "In2.Cu")
		(net "M_B_CPU0_SA_DQS_DN<4>")
	)
	(segment
		(start 336.195162 -260.430772)
		(end 336.011266 -260.614668)
		(width 0.088646)
		(layer "In2.Cu")
		(net "M_B_CPU0_SA_DQS_DN<4>")
	)
	(segment
		(start 304.380138 -274.71751)
		(end 303.829212 -274.71751)
		(width 0.18288)
		(layer "In2.Cu")
		(net "M_B_CPU0_SA_DQS_DN<4>")
	)
	(segment
		(start 297.298364 -275.194776)
		(end 297.27017 -275.166582)
		(width 0.16002)
		(layer "In2.Cu")
		(net "M_B_CPU0_SA_DQS_DN<4>")
	)
	(segment
		(start 300.373542 -275.660866)
		(end 300.345348 -275.632672)
		(width 0.16002)
		(layer "In2.Cu")
		(net "M_B_CPU0_SA_DQS_DN<4>")
	)
	(segment
		(start 304.81397 -275.151342)
		(end 304.797714 -275.151342)
		(width 0.16002)
		(layer "In2.Cu")
		(net "M_B_CPU0_SA_DQS_DN<4>")
	)
	(segment
		(start 296.760138 -274.65655)
		(end 295.98493 -274.65655)
		(width 0.18288)
		(layer "In2.Cu")
		(net "M_B_CPU0_SA_DQS_DN<4>")
	)
	(segment
		(start 295.65727 -274.98421)
		(end 295.221914 -274.98421)
		(width 0.18288)
		(layer "In2.Cu")
		(net "M_B_CPU0_SA_DQS_DN<4>")
	)
	(segment
		(start 302.313086 -275.677122)
		(end 302.113442 -275.876766)
		(width 0.16002)
		(layer "In2.Cu")
		(net "M_B_CPU0_SA_DQS_DN<4>")
	)
	(segment
		(start 310.378094 -274.822666)
		(end 310.153304 -275.364448)
		(width 0.18288)
		(layer "In2.Cu")
		(net "M_B_CPU0_SA_DQS_DN<4>")
	)
	(segment
		(start 316.339474 -271.380712)
		(end 315.951362 -271.768824)
		(width 0.18288)
		(layer "In2.Cu")
		(net "M_B_CPU0_SA_DQS_DN<4>")
	)
	(segment
		(start 300.373542 -275.677122)
		(end 300.373542 -275.660866)
		(width 0.16002)
		(layer "In2.Cu")
		(net "M_B_CPU0_SA_DQS_DN<4>")
	)
	(segment
		(start 310.153304 -275.364448)
		(end 309.88508 -275.632672)
		(width 0.18288)
		(layer "In2.Cu")
		(net "M_B_CPU0_SA_DQS_DN<4>")
	)
	(segment
		(start 311.851802 -273.36369)
		(end 311.836054 -273.36369)
		(width 0.16002)
		(layer "In2.Cu")
		(net "M_B_CPU0_SA_DQS_DN<4>")
	)
	(segment
		(start 302.34128 -275.632672)
		(end 302.313086 -275.660866)
		(width 0.16002)
		(layer "In2.Cu")
		(net "M_B_CPU0_SA_DQS_DN<4>")
	)
	(segment
		(start 328.962766 -262.704326)
		(end 326.869298 -262.704326)
		(width 0.18288)
		(layer "In2.Cu")
		(net "M_B_CPU0_SA_DQS_DN<4>")
	)
	(segment
		(start 319.75933 -267.960856)
		(end 319.75933 -268.136878)
		(width 0.18288)
		(layer "In2.Cu")
		(net "M_B_CPU0_SA_DQS_DN<4>")
	)
	(segment
		(start 299.456856 -275.349208)
		(end 299.1993 -275.091652)
		(width 0.18288)
		(layer "In2.Cu")
		(net "M_B_CPU0_SA_DQS_DN<4>")
	)
	(segment
		(start 318.41948 -269.476728)
		(end 318.243458 -269.476728)
		(width 0.18288)
		(layer "In2.Cu")
		(net "M_B_CPU0_SA_DQS_DN<4>")
	)
	(segment
		(start 302.626776 -275.347176)
		(end 302.34128 -275.632672)
		(width 0.18288)
		(layer "In2.Cu")
		(net "M_B_CPU0_SA_DQS_DN<4>")
	)
	(segment
		(start 317.467488 -270.42872)
		(end 317.291466 -270.42872)
		(width 0.18288)
		(layer "In2.Cu")
		(net "M_B_CPU0_SA_DQS_DN<4>")
	)
	(segment
		(start 313.553348 -272.82267)
		(end 312.377074 -272.82267)
		(width 0.18288)
		(layer "In2.Cu")
		(net "M_B_CPU0_SA_DQS_DN<4>")
	)
	(segment
		(start 306.371498 -275.089874)
		(end 306.099718 -275.361654)
		(width 0.18288)
		(layer "In2.Cu")
		(net "M_B_CPU0_SA_DQS_DN<4>")
	)
	(segment
		(start 329.31354 -262.704326)
		(end 328.962766 -262.704326)
		(width 0.088646)
		(layer "In2.Cu")
		(net "M_B_CPU0_SA_DQS_DN<4>")
	)
	(segment
		(start 308.161436 -275.90496)
		(end 308.133242 -275.876766)
		(width 0.16002)
		(layer "In2.Cu")
		(net "M_B_CPU0_SA_DQS_DN<4>")
	)
	(segment
		(start 315.563504 -272.332704)
		(end 315.387482 -272.332704)
		(width 0.18288)
		(layer "In2.Cu")
		(net "M_B_CPU0_SA_DQS_DN<4>")
	)
	(segment
		(start 306.996846 -275.361654)
		(end 306.725066 -275.089874)
		(width 0.18288)
		(layer "In2.Cu")
		(net "M_B_CPU0_SA_DQS_DN<4>")
	)
	(segment
		(start 314.038488 -273.323558)
		(end 313.838336 -273.123406)
		(width 0.16002)
		(layer "In2.Cu")
		(net "M_B_CPU0_SA_DQS_DN<4>")
	)
	(segment
		(start 307.917342 -275.660866)
		(end 307.889148 -275.632672)
		(width 0.16002)
		(layer "In2.Cu")
		(net "M_B_CPU0_SA_DQS_DN<4>")
	)
	(segment
		(start 311.329832 -273.87042)
		(end 311.15381 -273.87042)
		(width 0.18288)
		(layer "In2.Cu")
		(net "M_B_CPU0_SA_DQS_DN<4>")
	)
	(segment
		(start 318.243458 -269.476728)
		(end 317.855346 -269.86484)
		(width 0.18288)
		(layer "In2.Cu")
		(net "M_B_CPU0_SA_DQS_DN<4>")
	)
	(segment
		(start 300.573186 -275.876766)
		(end 300.373542 -275.677122)
		(width 0.16002)
		(layer "In2.Cu")
		(net "M_B_CPU0_SA_DQS_DN<4>")
	)
	(segment
		(start 309.88508 -275.632672)
		(end 309.856886 -275.660866)
		(width 0.16002)
		(layer "In2.Cu")
		(net "M_B_CPU0_SA_DQS_DN<4>")
	)
	(arc
		(start 332.248764 -260.75513)
		(mid 332.112394 -260.698677)
		(end 331.966062 -260.679438)
		(width 0.088646)
		(layer "In2.Cu")
		(net "M_B_CPU0_SA_DQS_DN<4>")
	)
	(arc
		(start 333.56296 -260.75513)
		(mid 333.375762 -260.805273)
		(end 333.188564 -260.75513)
		(width 0.088646)
		(layer "In2.Cu")
		(net "M_B_CPU0_SA_DQS_DN<4>")
	)
	(arc
		(start 334.50276 -260.75513)
		(mid 334.315562 -260.805273)
		(end 334.128364 -260.75513)
		(width 0.088646)
		(layer "In2.Cu")
		(net "M_B_CPU0_SA_DQS_DN<4>")
	)
	(arc
		(start 333.188564 -260.75513)
		(mid 332.905862 -260.679388)
		(end 332.62316 -260.75513)
		(width 0.088646)
		(layer "In2.Cu")
		(net "M_B_CPU0_SA_DQS_DN<4>")
	)
	(arc
		(start 335.442306 -260.755384)
		(mid 335.255252 -260.8054)
		(end 335.068164 -260.755384)
		(width 0.088646)
		(layer "In2.Cu")
		(net "M_B_CPU0_SA_DQS_DN<4>")
	)
	(arc
		(start 332.62316 -260.75513)
		(mid 332.435962 -260.805273)
		(end 332.248764 -260.75513)
		(width 0.088646)
		(layer "In2.Cu")
		(net "M_B_CPU0_SA_DQS_DN<4>")
	)
	(arc
		(start 335.967324 -260.614668)
		(mid 335.695546 -260.65045)
		(end 335.442306 -260.755384)
		(width 0.088646)
		(layer "In2.Cu")
		(net "M_B_CPU0_SA_DQS_DN<4>")
	)
	(arc
		(start 334.128364 -260.75513)
		(mid 333.845662 -260.679388)
		(end 333.56296 -260.75513)
		(width 0.088646)
		(layer "In2.Cu")
		(net "M_B_CPU0_SA_DQS_DN<4>")
	)
	(arc
		(start 335.068164 -260.75513)
		(mid 334.785462 -260.679388)
		(end 334.50276 -260.75513)
		(width 0.088646)
		(layer "In2.Cu")
		(net "M_B_CPU0_SA_DQS_DN<4>")
	)
	(segment
		(start 339.484716 -262.336534)
		(end 339.484716 -262.87222)
		(width 0.20066)
		(layer "F.Cu")
		(net "M_B_CPU0_SA_DQS_DN<3>")
	)
	(segment
		(start 292.58514 -284.277816)
		(end 292.159944 -284.703012)
		(width 0.20066)
		(layer "F.Cu")
		(net "M_B_CPU0_SA_DQS_DN<3>")
	)
	(segment
		(start 289.243008 -284.441646)
		(end 289.23234 -284.430978)
		(width 0.101854)
		(layer "F.Cu")
		(net "M_B_CPU0_SA_DQS_DN<3>")
	)
	(segment
		(start 291.556694 -284.441646)
		(end 289.243008 -284.441646)
		(width 0.1016)
		(layer "F.Cu")
		(net "M_B_CPU0_SA_DQS_DN<3>")
	)
	(segment
		(start 294.904414 -284.016704)
		(end 293.799514 -284.016704)
		(width 0.20066)
		(layer "F.Cu")
		(net "M_B_CPU0_SA_DQS_DN<3>")
	)
	(segment
		(start 289.231578 -284.430978)
		(end 289.027362 -284.430978)
		(width 0.20066)
		(layer "F.Cu")
		(net "M_B_CPU0_SA_DQS_DN<3>")
	)
	(segment
		(start 292.991794 -284.277816)
		(end 292.58514 -284.277816)
		(width 0.20066)
		(layer "F.Cu")
		(net "M_B_CPU0_SA_DQS_DN<3>")
	)
	(segment
		(start 291.973254 -284.703012)
		(end 291.711888 -284.441646)
		(width 0.20066)
		(layer "F.Cu")
		(net "M_B_CPU0_SA_DQS_DN<3>")
	)
	(segment
		(start 288.755328 -284.703012)
		(end 288.215324 -284.703012)
		(width 0.20066)
		(layer "F.Cu")
		(net "M_B_CPU0_SA_DQS_DN<3>")
	)
	(segment
		(start 339.484716 -262.87222)
		(end 339.484462 -262.872474)
		(width 0.20066)
		(layer "F.Cu")
		(net "M_B_CPU0_SA_DQS_DN<3>")
	)
	(segment
		(start 289.027362 -284.430978)
		(end 288.755328 -284.703012)
		(width 0.20066)
		(layer "F.Cu")
		(net "M_B_CPU0_SA_DQS_DN<3>")
	)
	(segment
		(start 286.804354 -284.016704)
		(end 286.255714 -284.016704)
		(width 0.20066)
		(layer "F.Cu")
		(net "M_B_CPU0_SA_DQS_DN<3>")
	)
	(segment
		(start 287.579308 -284.277816)
		(end 287.065466 -284.277816)
		(width 0.20066)
		(layer "F.Cu")
		(net "M_B_CPU0_SA_DQS_DN<3>")
	)
	(segment
		(start 293.252906 -284.016704)
		(end 292.991794 -284.277816)
		(width 0.20066)
		(layer "F.Cu")
		(net "M_B_CPU0_SA_DQS_DN<3>")
	)
	(segment
		(start 287.065466 -284.277816)
		(end 286.804354 -284.016704)
		(width 0.20066)
		(layer "F.Cu")
		(net "M_B_CPU0_SA_DQS_DN<3>")
	)
	(segment
		(start 289.23234 -284.430978)
		(end 289.231578 -284.430978)
		(width 0.101854)
		(layer "F.Cu")
		(net "M_B_CPU0_SA_DQS_DN<3>")
	)
	(segment
		(start 293.799514 -284.016704)
		(end 293.252906 -284.016704)
		(width 0.20066)
		(layer "F.Cu")
		(net "M_B_CPU0_SA_DQS_DN<3>")
	)
	(segment
		(start 288.215324 -284.703012)
		(end 287.579308 -284.277816)
		(width 0.20066)
		(layer "F.Cu")
		(net "M_B_CPU0_SA_DQS_DN<3>")
	)
	(segment
		(start 291.711888 -284.441646)
		(end 291.556694 -284.441646)
		(width 0.20066)
		(layer "F.Cu")
		(net "M_B_CPU0_SA_DQS_DN<3>")
	)
	(segment
		(start 292.159944 -284.703012)
		(end 291.973254 -284.703012)
		(width 0.20066)
		(layer "F.Cu")
		(net "M_B_CPU0_SA_DQS_DN<3>")
	)
	(segment
		(start 338.985606 -263.05129)
		(end 338.732368 -263.197086)
		(width 0.088646)
		(layer "In4.Cu")
		(net "M_B_CPU0_SA_DQS_DN<3>")
	)
	(segment
		(start 339.452712 -262.988298)
		(end 339.41385 -263.010396)
		(width 0.088646)
		(layer "In4.Cu")
		(net "M_B_CPU0_SA_DQS_DN<3>")
	)
	(segment
		(start 295.886124 -284.09265)
		(end 295.703244 -284.27553)
		(width 0.18288)
		(layer "In4.Cu")
		(net "M_B_CPU0_SA_DQS_DN<3>")
	)
	(segment
		(start 317.582296 -272.522188)
		(end 316.378844 -273.72564)
		(width 0.18288)
		(layer "In4.Cu")
		(net "M_B_CPU0_SA_DQS_DN<3>")
	)
	(segment
		(start 321.954398 -268.150086)
		(end 321.778376 -268.150086)
		(width 0.18288)
		(layer "In4.Cu")
		(net "M_B_CPU0_SA_DQS_DN<3>")
	)
	(segment
		(start 330.833984 -263.32815)
		(end 330.774294 -263.26846)
		(width 0.088646)
		(layer "In4.Cu")
		(net "M_B_CPU0_SA_DQS_DN<3>")
	)
	(segment
		(start 299.425868 -284.687264)
		(end 299.270928 -284.532578)
		(width 0.18288)
		(layer "In4.Cu")
		(net "M_B_CPU0_SA_DQS_DN<3>")
	)
	(segment
		(start 317.582296 -272.346166)
		(end 317.582296 -272.522188)
		(width 0.18288)
		(layer "In4.Cu")
		(net "M_B_CPU0_SA_DQS_DN<3>")
	)
	(segment
		(start 303.400206 -282.36672)
		(end 303.049432 -283.213556)
		(width 0.18288)
		(layer "In4.Cu")
		(net "M_B_CPU0_SA_DQS_DN<3>")
	)
	(segment
		(start 325.76262 -264.342118)
		(end 325.586344 -264.342118)
		(width 0.18288)
		(layer "In4.Cu")
		(net "M_B_CPU0_SA_DQS_DN<3>")
	)
	(segment
		(start 322.90639 -267.198094)
		(end 322.730368 -267.198094)
		(width 0.18288)
		(layer "In4.Cu")
		(net "M_B_CPU0_SA_DQS_DN<3>")
	)
	(segment
		(start 325.586344 -264.342118)
		(end 325.198232 -264.73023)
		(width 0.18288)
		(layer "In4.Cu")
		(net "M_B_CPU0_SA_DQS_DN<3>")
	)
	(segment
		(start 322.342256 -267.762228)
		(end 321.954398 -268.150086)
		(width 0.18288)
		(layer "In4.Cu")
		(net "M_B_CPU0_SA_DQS_DN<3>")
	)
	(segment
		(start 306.138326 -281.26055)
		(end 304.326798 -281.26055)
		(width 0.18288)
		(layer "In4.Cu")
		(net "M_B_CPU0_SA_DQS_DN<3>")
	)
	(segment
		(start 322.342256 -267.586206)
		(end 322.342256 -267.762228)
		(width 0.18288)
		(layer "In4.Cu")
		(net "M_B_CPU0_SA_DQS_DN<3>")
	)
	(segment
		(start 309.792116 -278.770334)
		(end 308.125368 -280.437082)
		(width 0.18288)
		(layer "In4.Cu")
		(net "M_B_CPU0_SA_DQS_DN<3>")
	)
	(segment
		(start 297.632882 -284.09265)
		(end 295.886124 -284.09265)
		(width 0.18288)
		(layer "In4.Cu")
		(net "M_B_CPU0_SA_DQS_DN<3>")
	)
	(segment
		(start 324.24624 -265.682222)
		(end 324.24624 -265.858244)
		(width 0.18288)
		(layer "In4.Cu")
		(net "M_B_CPU0_SA_DQS_DN<3>")
	)
	(segment
		(start 299.270928 -284.532578)
		(end 299.180504 -284.442154)
		(width 0.18288)
		(layer "In4.Cu")
		(net "M_B_CPU0_SA_DQS_DN<3>")
	)
	(segment
		(start 313.423808 -275.138134)
		(end 312.579258 -277.176484)
		(width 0.18288)
		(layer "In4.Cu")
		(net "M_B_CPU0_SA_DQS_DN<3>")
	)
	(segment
		(start 320.826384 -269.102078)
		(end 320.438272 -269.49019)
		(width 0.18288)
		(layer "In4.Cu")
		(net "M_B_CPU0_SA_DQS_DN<3>")
	)
	(segment
		(start 312.579258 -277.176484)
		(end 312.235596 -277.5204)
		(width 0.18288)
		(layer "In4.Cu")
		(net "M_B_CPU0_SA_DQS_DN<3>")
	)
	(segment
		(start 313.555634 -274.992592)
		(end 313.423808 -275.138134)
		(width 0.18288)
		(layer "In4.Cu")
		(net "M_B_CPU0_SA_DQS_DN<3>")
	)
	(segment
		(start 338.732368 -263.197086)
		(end 338.732114 -263.196832)
		(width 0.088646)
		(layer "In4.Cu")
		(net "M_B_CPU0_SA_DQS_DN<3>")
	)
	(segment
		(start 330.774294 -263.26846)
		(end 330.724002 -263.26846)
		(width 0.088646)
		(layer "In4.Cu")
		(net "M_B_CPU0_SA_DQS_DN<3>")
	)
	(segment
		(start 298.54017 -284.714696)
		(end 298.254928 -284.714696)
		(width 0.18288)
		(layer "In4.Cu")
		(net "M_B_CPU0_SA_DQS_DN<3>")
	)
	(segment
		(start 324.810374 -265.29411)
		(end 324.634352 -265.29411)
		(width 0.18288)
		(layer "In4.Cu")
		(net "M_B_CPU0_SA_DQS_DN<3>")
	)
	(segment
		(start 331.591412 -263.147048)
		(end 331.26934 -263.147048)
		(width 0.088646)
		(layer "In4.Cu")
		(net "M_B_CPU0_SA_DQS_DN<3>")
	)
	(segment
		(start 300.534578 -284.470602)
		(end 299.94987 -284.470602)
		(width 0.18288)
		(layer "In4.Cu")
		(net "M_B_CPU0_SA_DQS_DN<3>")
	)
	(segment
		(start 324.634352 -265.29411)
		(end 324.24624 -265.682222)
		(width 0.18288)
		(layer "In4.Cu")
		(net "M_B_CPU0_SA_DQS_DN<3>")
	)
	(segment
		(start 323.294248 -266.810236)
		(end 322.90639 -267.198094)
		(width 0.18288)
		(layer "In4.Cu")
		(net "M_B_CPU0_SA_DQS_DN<3>")
	)
	(segment
		(start 323.294248 -266.634214)
		(end 323.294248 -266.810236)
		(width 0.18288)
		(layer "In4.Cu")
		(net "M_B_CPU0_SA_DQS_DN<3>")
	)
	(segment
		(start 331.26934 -263.147048)
		(end 331.088238 -263.32815)
		(width 0.088646)
		(layer "In4.Cu")
		(net "M_B_CPU0_SA_DQS_DN<3>")
	)
	(segment
		(start 311.300114 -278.145494)
		(end 309.792116 -278.770334)
		(width 0.18288)
		(layer "In4.Cu")
		(net "M_B_CPU0_SA_DQS_DN<3>")
	)
	(segment
		(start 339.484462 -262.872474)
		(end 339.452712 -262.988298)
		(width 0.088646)
		(layer "In4.Cu")
		(net "M_B_CPU0_SA_DQS_DN<3>")
	)
	(segment
		(start 313.698636 -274.834858)
		(end 313.555634 -274.992592)
		(width 0.18288)
		(layer "In4.Cu")
		(net "M_B_CPU0_SA_DQS_DN<3>")
	)
	(segment
		(start 299.180504 -284.442154)
		(end 298.812712 -284.442154)
		(width 0.18288)
		(layer "In4.Cu")
		(net "M_B_CPU0_SA_DQS_DN<3>")
	)
	(segment
		(start 312.235596 -277.5204)
		(end 311.300114 -278.145494)
		(width 0.18288)
		(layer "In4.Cu")
		(net "M_B_CPU0_SA_DQS_DN<3>")
	)
	(segment
		(start 299.94987 -284.470602)
		(end 299.425868 -284.687264)
		(width 0.18288)
		(layer "In4.Cu")
		(net "M_B_CPU0_SA_DQS_DN<3>")
	)
	(segment
		(start 323.68236 -266.246102)
		(end 323.294248 -266.634214)
		(width 0.18288)
		(layer "In4.Cu")
		(net "M_B_CPU0_SA_DQS_DN<3>")
	)
	(segment
		(start 324.24624 -265.858244)
		(end 323.858382 -266.246102)
		(width 0.18288)
		(layer "In4.Cu")
		(net "M_B_CPU0_SA_DQS_DN<3>")
	)
	(segment
		(start 321.390264 -268.538198)
		(end 321.390264 -268.71422)
		(width 0.18288)
		(layer "In4.Cu")
		(net "M_B_CPU0_SA_DQS_DN<3>")
	)
	(segment
		(start 303.762156 -281.825192)
		(end 303.400206 -282.36672)
		(width 0.18288)
		(layer "In4.Cu")
		(net "M_B_CPU0_SA_DQS_DN<3>")
	)
	(segment
		(start 321.002406 -269.102078)
		(end 320.826384 -269.102078)
		(width 0.18288)
		(layer "In4.Cu")
		(net "M_B_CPU0_SA_DQS_DN<3>")
	)
	(segment
		(start 320.438272 -269.666212)
		(end 320.050414 -270.05407)
		(width 0.18288)
		(layer "In4.Cu")
		(net "M_B_CPU0_SA_DQS_DN<3>")
	)
	(segment
		(start 330.724002 -263.26846)
		(end 327.805288 -263.26846)
		(width 0.18288)
		(layer "In4.Cu")
		(net "M_B_CPU0_SA_DQS_DN<3>")
	)
	(segment
		(start 319.098422 -271.006062)
		(end 318.9224 -271.006062)
		(width 0.18288)
		(layer "In4.Cu")
		(net "M_B_CPU0_SA_DQS_DN<3>")
	)
	(segment
		(start 304.326798 -281.26055)
		(end 303.762156 -281.825192)
		(width 0.18288)
		(layer "In4.Cu")
		(net "M_B_CPU0_SA_DQS_DN<3>")
	)
	(segment
		(start 331.088238 -263.32815)
		(end 330.833984 -263.32815)
		(width 0.088646)
		(layer "In4.Cu")
		(net "M_B_CPU0_SA_DQS_DN<3>")
	)
	(segment
		(start 298.812712 -284.442154)
		(end 298.54017 -284.714696)
		(width 0.18288)
		(layer "In4.Cu")
		(net "M_B_CPU0_SA_DQS_DN<3>")
	)
	(segment
		(start 321.778376 -268.150086)
		(end 321.390264 -268.538198)
		(width 0.18288)
		(layer "In4.Cu")
		(net "M_B_CPU0_SA_DQS_DN<3>")
	)
	(segment
		(start 303.049432 -283.213556)
		(end 302.682148 -283.58084)
		(width 0.18288)
		(layer "In4.Cu")
		(net "M_B_CPU0_SA_DQS_DN<3>")
	)
	(segment
		(start 325.198232 -264.906252)
		(end 324.810374 -265.29411)
		(width 0.18288)
		(layer "In4.Cu")
		(net "M_B_CPU0_SA_DQS_DN<3>")
	)
	(segment
		(start 327.805288 -263.26846)
		(end 326.150224 -263.95426)
		(width 0.18288)
		(layer "In4.Cu")
		(net "M_B_CPU0_SA_DQS_DN<3>")
	)
	(segment
		(start 302.682148 -283.58084)
		(end 300.534578 -284.470602)
		(width 0.18288)
		(layer "In4.Cu")
		(net "M_B_CPU0_SA_DQS_DN<3>")
	)
	(segment
		(start 320.438272 -269.49019)
		(end 320.438272 -269.666212)
		(width 0.18288)
		(layer "In4.Cu")
		(net "M_B_CPU0_SA_DQS_DN<3>")
	)
	(segment
		(start 295.16324 -284.27553)
		(end 294.904414 -284.016704)
		(width 0.18288)
		(layer "In4.Cu")
		(net "M_B_CPU0_SA_DQS_DN<3>")
	)
	(segment
		(start 318.14643 -271.958054)
		(end 317.970408 -271.958054)
		(width 0.18288)
		(layer "In4.Cu")
		(net "M_B_CPU0_SA_DQS_DN<3>")
	)
	(segment
		(start 321.390264 -268.71422)
		(end 321.002406 -269.102078)
		(width 0.18288)
		(layer "In4.Cu")
		(net "M_B_CPU0_SA_DQS_DN<3>")
	)
	(segment
		(start 318.534288 -271.394174)
		(end 318.534288 -271.570196)
		(width 0.18288)
		(layer "In4.Cu")
		(net "M_B_CPU0_SA_DQS_DN<3>")
	)
	(segment
		(start 298.254928 -284.714696)
		(end 297.632882 -284.09265)
		(width 0.18288)
		(layer "In4.Cu")
		(net "M_B_CPU0_SA_DQS_DN<3>")
	)
	(segment
		(start 318.534288 -271.570196)
		(end 318.14643 -271.958054)
		(width 0.18288)
		(layer "In4.Cu")
		(net "M_B_CPU0_SA_DQS_DN<3>")
	)
	(segment
		(start 316.378844 -273.72564)
		(end 313.698636 -274.834858)
		(width 0.18288)
		(layer "In4.Cu")
		(net "M_B_CPU0_SA_DQS_DN<3>")
	)
	(segment
		(start 337.802474 -263.190736)
		(end 337.79206 -263.196832)
		(width 0.088646)
		(layer "In4.Cu")
		(net "M_B_CPU0_SA_DQS_DN<3>")
	)
	(segment
		(start 320.050414 -270.05407)
		(end 319.874392 -270.05407)
		(width 0.18288)
		(layer "In4.Cu")
		(net "M_B_CPU0_SA_DQS_DN<3>")
	)
	(segment
		(start 322.730368 -267.198094)
		(end 322.342256 -267.586206)
		(width 0.18288)
		(layer "In4.Cu")
		(net "M_B_CPU0_SA_DQS_DN<3>")
	)
	(segment
		(start 325.198232 -264.73023)
		(end 325.198232 -264.906252)
		(width 0.18288)
		(layer "In4.Cu")
		(net "M_B_CPU0_SA_DQS_DN<3>")
	)
	(segment
		(start 317.970408 -271.958054)
		(end 317.582296 -272.346166)
		(width 0.18288)
		(layer "In4.Cu")
		(net "M_B_CPU0_SA_DQS_DN<3>")
	)
	(segment
		(start 319.48628 -270.442182)
		(end 319.48628 -270.618204)
		(width 0.18288)
		(layer "In4.Cu")
		(net "M_B_CPU0_SA_DQS_DN<3>")
	)
	(segment
		(start 339.259164 -263.05129)
		(end 338.985606 -263.05129)
		(width 0.088646)
		(layer "In4.Cu")
		(net "M_B_CPU0_SA_DQS_DN<3>")
	)
	(segment
		(start 326.150224 -263.95426)
		(end 325.76262 -264.342118)
		(width 0.18288)
		(layer "In4.Cu")
		(net "M_B_CPU0_SA_DQS_DN<3>")
	)
	(segment
		(start 319.874392 -270.05407)
		(end 319.48628 -270.442182)
		(width 0.18288)
		(layer "In4.Cu")
		(net "M_B_CPU0_SA_DQS_DN<3>")
	)
	(segment
		(start 295.703244 -284.27553)
		(end 295.16324 -284.27553)
		(width 0.18288)
		(layer "In4.Cu")
		(net "M_B_CPU0_SA_DQS_DN<3>")
	)
	(segment
		(start 319.48628 -270.618204)
		(end 319.098422 -271.006062)
		(width 0.18288)
		(layer "In4.Cu")
		(net "M_B_CPU0_SA_DQS_DN<3>")
	)
	(segment
		(start 308.125368 -280.437082)
		(end 306.138326 -281.26055)
		(width 0.18288)
		(layer "In4.Cu")
		(net "M_B_CPU0_SA_DQS_DN<3>")
	)
	(segment
		(start 323.858382 -266.246102)
		(end 323.68236 -266.246102)
		(width 0.18288)
		(layer "In4.Cu")
		(net "M_B_CPU0_SA_DQS_DN<3>")
	)
	(segment
		(start 318.9224 -271.006062)
		(end 318.534288 -271.394174)
		(width 0.18288)
		(layer "In4.Cu")
		(net "M_B_CPU0_SA_DQS_DN<3>")
	)
	(arc
		(start 333.09306 -263.196832)
		(mid 332.905862 -263.246975)
		(end 332.718664 -263.196832)
		(width 0.088646)
		(layer "In4.Cu")
		(net "M_B_CPU0_SA_DQS_DN<3>")
	)
	(arc
		(start 334.03286 -263.196832)
		(mid 333.845662 -263.246975)
		(end 333.658464 -263.196832)
		(width 0.088646)
		(layer "In4.Cu")
		(net "M_B_CPU0_SA_DQS_DN<3>")
	)
	(arc
		(start 332.153768 -263.19734)
		(mid 331.966345 -263.247669)
		(end 331.778864 -263.197594)
		(width 0.088646)
		(layer "In4.Cu")
		(net "M_B_CPU0_SA_DQS_DN<3>")
	)
	(arc
		(start 335.538064 -263.196832)
		(mid 335.255362 -263.12109)
		(end 334.97266 -263.196832)
		(width 0.088646)
		(layer "In4.Cu")
		(net "M_B_CPU0_SA_DQS_DN<3>")
	)
	(arc
		(start 334.598264 -263.196832)
		(mid 334.315562 -263.12109)
		(end 334.03286 -263.196832)
		(width 0.088646)
		(layer "In4.Cu")
		(net "M_B_CPU0_SA_DQS_DN<3>")
	)
	(arc
		(start 334.97266 -263.196832)
		(mid 334.785462 -263.246975)
		(end 334.598264 -263.196832)
		(width 0.088646)
		(layer "In4.Cu")
		(net "M_B_CPU0_SA_DQS_DN<3>")
	)
	(arc
		(start 337.79206 -263.196832)
		(mid 337.604862 -263.246975)
		(end 337.417664 -263.196832)
		(width 0.088646)
		(layer "In4.Cu")
		(net "M_B_CPU0_SA_DQS_DN<3>")
	)
	(arc
		(start 338.732114 -263.196832)
		(mid 338.544916 -263.246975)
		(end 338.357718 -263.196832)
		(width 0.088646)
		(layer "In4.Cu")
		(net "M_B_CPU0_SA_DQS_DN<3>")
	)
	(arc
		(start 338.357718 -263.196832)
		(mid 338.080905 -263.120996)
		(end 337.802474 -263.190736)
		(width 0.088646)
		(layer "In4.Cu")
		(net "M_B_CPU0_SA_DQS_DN<3>")
	)
	(arc
		(start 337.417664 -263.196832)
		(mid 337.134962 -263.12109)
		(end 336.85226 -263.196832)
		(width 0.088646)
		(layer "In4.Cu")
		(net "M_B_CPU0_SA_DQS_DN<3>")
	)
	(arc
		(start 336.85226 -263.196832)
		(mid 336.665062 -263.246975)
		(end 336.477864 -263.196832)
		(width 0.088646)
		(layer "In4.Cu")
		(net "M_B_CPU0_SA_DQS_DN<3>")
	)
	(arc
		(start 339.41385 -263.010396)
		(mid 339.339165 -263.040901)
		(end 339.259164 -263.05129)
		(width 0.088646)
		(layer "In4.Cu")
		(net "M_B_CPU0_SA_DQS_DN<3>")
	)
	(arc
		(start 331.778864 -263.197594)
		(mid 331.688475 -263.159947)
		(end 331.591412 -263.147048)
		(width 0.088646)
		(layer "In4.Cu")
		(net "M_B_CPU0_SA_DQS_DN<3>")
	)
	(arc
		(start 332.718664 -263.196832)
		(mid 332.436157 -263.121471)
		(end 332.153768 -263.19734)
		(width 0.088646)
		(layer "In4.Cu")
		(net "M_B_CPU0_SA_DQS_DN<3>")
	)
	(arc
		(start 335.91246 -263.196832)
		(mid 335.725262 -263.246975)
		(end 335.538064 -263.196832)
		(width 0.088646)
		(layer "In4.Cu")
		(net "M_B_CPU0_SA_DQS_DN<3>")
	)
	(arc
		(start 333.658464 -263.196832)
		(mid 333.375762 -263.12109)
		(end 333.09306 -263.196832)
		(width 0.088646)
		(layer "In4.Cu")
		(net "M_B_CPU0_SA_DQS_DN<3>")
	)
	(arc
		(start 336.477864 -263.196832)
		(mid 336.195162 -263.12109)
		(end 335.91246 -263.196832)
		(width 0.088646)
		(layer "In4.Cu")
		(net "M_B_CPU0_SA_DQS_DN<3>")
	)
	(segment
		(start 289.243008 -293.79164)
		(end 289.23234 -293.780972)
		(width 0.101854)
		(layer "F.Cu")
		(net "M_B_CPU0_SA_DQS_DN<2>")
	)
	(segment
		(start 291.973254 -294.053006)
		(end 291.711888 -293.79164)
		(width 0.20066)
		(layer "F.Cu")
		(net "M_B_CPU0_SA_DQS_DN<2>")
	)
	(segment
		(start 336.195162 -264.778236)
		(end 336.195162 -265.314176)
		(width 0.20066)
		(layer "F.Cu")
		(net "M_B_CPU0_SA_DQS_DN<2>")
	)
	(segment
		(start 288.215324 -294.053006)
		(end 287.579308 -293.62781)
		(width 0.20066)
		(layer "F.Cu")
		(net "M_B_CPU0_SA_DQS_DN<2>")
	)
	(segment
		(start 287.065466 -293.62781)
		(end 286.804354 -293.366698)
		(width 0.20066)
		(layer "F.Cu")
		(net "M_B_CPU0_SA_DQS_DN<2>")
	)
	(segment
		(start 287.579308 -293.62781)
		(end 287.065466 -293.62781)
		(width 0.20066)
		(layer "F.Cu")
		(net "M_B_CPU0_SA_DQS_DN<2>")
	)
	(segment
		(start 294.904414 -293.366698)
		(end 293.799514 -293.366698)
		(width 0.20066)
		(layer "F.Cu")
		(net "M_B_CPU0_SA_DQS_DN<2>")
	)
	(segment
		(start 291.711888 -293.79164)
		(end 291.556694 -293.79164)
		(width 0.20066)
		(layer "F.Cu")
		(net "M_B_CPU0_SA_DQS_DN<2>")
	)
	(segment
		(start 293.799514 -293.366698)
		(end 293.252906 -293.366698)
		(width 0.20066)
		(layer "F.Cu")
		(net "M_B_CPU0_SA_DQS_DN<2>")
	)
	(segment
		(start 286.804354 -293.366698)
		(end 286.255714 -293.366698)
		(width 0.20066)
		(layer "F.Cu")
		(net "M_B_CPU0_SA_DQS_DN<2>")
	)
	(segment
		(start 288.755328 -294.053006)
		(end 288.215324 -294.053006)
		(width 0.20066)
		(layer "F.Cu")
		(net "M_B_CPU0_SA_DQS_DN<2>")
	)
	(segment
		(start 289.231578 -293.780972)
		(end 289.027362 -293.780972)
		(width 0.20066)
		(layer "F.Cu")
		(net "M_B_CPU0_SA_DQS_DN<2>")
	)
	(segment
		(start 289.23234 -293.780972)
		(end 289.231578 -293.780972)
		(width 0.101854)
		(layer "F.Cu")
		(net "M_B_CPU0_SA_DQS_DN<2>")
	)
	(segment
		(start 292.58514 -293.62781)
		(end 292.159944 -294.053006)
		(width 0.20066)
		(layer "F.Cu")
		(net "M_B_CPU0_SA_DQS_DN<2>")
	)
	(segment
		(start 292.159944 -294.053006)
		(end 291.973254 -294.053006)
		(width 0.20066)
		(layer "F.Cu")
		(net "M_B_CPU0_SA_DQS_DN<2>")
	)
	(segment
		(start 293.252906 -293.366698)
		(end 292.991794 -293.62781)
		(width 0.20066)
		(layer "F.Cu")
		(net "M_B_CPU0_SA_DQS_DN<2>")
	)
	(segment
		(start 289.027362 -293.780972)
		(end 288.755328 -294.053006)
		(width 0.20066)
		(layer "F.Cu")
		(net "M_B_CPU0_SA_DQS_DN<2>")
	)
	(segment
		(start 292.991794 -293.62781)
		(end 292.58514 -293.62781)
		(width 0.20066)
		(layer "F.Cu")
		(net "M_B_CPU0_SA_DQS_DN<2>")
	)
	(segment
		(start 291.556694 -293.79164)
		(end 289.243008 -293.79164)
		(width 0.1016)
		(layer "F.Cu")
		(net "M_B_CPU0_SA_DQS_DN<2>")
	)
	(segment
		(start 325.214488 -271.770348)
		(end 325.214488 -271.94637)
		(width 0.18288)
		(layer "In2.Cu")
		(net "M_B_CPU0_SA_DQS_DN<2>")
	)
	(segment
		(start 313.712352 -284.437074)
		(end 313.696096 -284.437074)
		(width 0.16002)
		(layer "In2.Cu")
		(net "M_B_CPU0_SA_DQS_DN<2>")
	)
	(segment
		(start 302.701706 -293.972234)
		(end 302.34128 -294.33266)
		(width 0.18288)
		(layer "In2.Cu")
		(net "M_B_CPU0_SA_DQS_DN<2>")
	)
	(segment
		(start 327.506584 -269.478252)
		(end 327.118472 -269.866364)
		(width 0.18288)
		(layer "In2.Cu")
		(net "M_B_CPU0_SA_DQS_DN<2>")
	)
	(segment
		(start 300.617636 -294.604948)
		(end 300.589442 -294.576754)
		(width 0.16002)
		(layer "In2.Cu")
		(net "M_B_CPU0_SA_DQS_DN<2>")
	)
	(segment
		(start 297.05427 -293.666926)
		(end 297.05427 -293.65067)
		(width 0.16002)
		(layer "In2.Cu")
		(net "M_B_CPU0_SA_DQS_DN<2>")
	)
	(segment
		(start 306.305458 -291.059108)
		(end 306.305458 -291.082476)
		(width 0.16002)
		(layer "In2.Cu")
		(net "M_B_CPU0_SA_DQS_DN<2>")
	)
	(segment
		(start 300.732698 -294.72001)
		(end 300.617636 -294.604948)
		(width 0.18288)
		(layer "In2.Cu")
		(net "M_B_CPU0_SA_DQS_DN<2>")
	)
	(segment
		(start 328.477118 -268.830298)
		(end 328.226928 -268.93393)
		(width 0.18288)
		(layer "In2.Cu")
		(net "M_B_CPU0_SA_DQS_DN<2>")
	)
	(segment
		(start 322.358512 -274.626324)
		(end 322.358512 -274.802346)
		(width 0.18288)
		(layer "In2.Cu")
		(net "M_B_CPU0_SA_DQS_DN<2>")
	)
	(segment
		(start 318.360044 -278.800814)
		(end 318.360044 -280.140664)
		(width 0.18288)
		(layer "In2.Cu")
		(net "M_B_CPU0_SA_DQS_DN<2>")
	)
	(segment
		(start 321.970654 -275.190204)
		(end 321.794632 -275.190204)
		(width 0.18288)
		(layer "In2.Cu")
		(net "M_B_CPU0_SA_DQS_DN<2>")
	)
	(segment
		(start 304.498502 -291.909246)
		(end 304.470308 -291.93744)
		(width 0.16002)
		(layer "In2.Cu")
		(net "M_B_CPU0_SA_DQS_DN<2>")
	)
	(segment
		(start 304.470308 -291.93744)
		(end 304.470308 -291.953188)
		(width 0.16002)
		(layer "In2.Cu")
		(net "M_B_CPU0_SA_DQS_DN<2>")
	)
	(segment
		(start 306.06492 -291.306758)
		(end 305.760628 -291.61105)
		(width 0.18288)
		(layer "In2.Cu")
		(net "M_B_CPU0_SA_DQS_DN<2>")
	)
	(segment
		(start 319.502536 -277.658322)
		(end 318.360044 -278.800814)
		(width 0.18288)
		(layer "In2.Cu")
		(net "M_B_CPU0_SA_DQS_DN<2>")
	)
	(segment
		(start 306.305458 -291.082476)
		(end 306.10937 -291.278564)
		(width 0.16002)
		(layer "In2.Cu")
		(net "M_B_CPU0_SA_DQS_DN<2>")
	)
	(segment
		(start 297.468036 -294.064436)
		(end 297.298364 -293.894764)
		(width 0.18288)
		(layer "In2.Cu")
		(net "M_B_CPU0_SA_DQS_DN<2>")
	)
	(segment
		(start 313.911996 -284.23743)
		(end 313.712352 -284.437074)
		(width 0.16002)
		(layer "In2.Cu")
		(net "M_B_CPU0_SA_DQS_DN<2>")
	)
	(segment
		(start 318.360044 -280.140664)
		(end 317.822072 -280.678636)
		(width 0.18288)
		(layer "In2.Cu")
		(net "M_B_CPU0_SA_DQS_DN<2>")
	)
	(segment
		(start 323.874638 -273.28622)
		(end 323.698616 -273.28622)
		(width 0.18288)
		(layer "In2.Cu")
		(net "M_B_CPU0_SA_DQS_DN<2>")
	)
	(segment
		(start 299.298106 -293.79164)
		(end 298.801028 -293.79164)
		(width 0.18288)
		(layer "In2.Cu")
		(net "M_B_CPU0_SA_DQS_DN<2>")
	)
	(segment
		(start 300.573186 -294.576754)
		(end 300.373542 -294.37711)
		(width 0.16002)
		(layer "In2.Cu")
		(net "M_B_CPU0_SA_DQS_DN<2>")
	)
	(segment
		(start 300.07052 -294.057832)
		(end 299.564298 -294.057832)
		(width 0.18288)
		(layer "In2.Cu")
		(net "M_B_CPU0_SA_DQS_DN<2>")
	)
	(segment
		(start 311.814972 -285.321248)
		(end 311.06745 -286.06877)
		(width 0.18288)
		(layer "In2.Cu")
		(net "M_B_CPU0_SA_DQS_DN<2>")
	)
	(segment
		(start 295.1861 -293.648384)
		(end 294.904414 -293.366698)
		(width 0.18288)
		(layer "In2.Cu")
		(net "M_B_CPU0_SA_DQS_DN<2>")
	)
	(segment
		(start 316.305692 -282.018994)
		(end 316.305692 -282.195016)
		(width 0.18288)
		(layer "In2.Cu")
		(net "M_B_CPU0_SA_DQS_DN<2>")
	)
	(segment
		(start 336.155792 -265.314176)
		(end 335.973928 -265.49604)
		(width 0.088646)
		(layer "In2.Cu")
		(net "M_B_CPU0_SA_DQS_DN<2>")
	)
	(segment
		(start 310.514238 -286.06877)
		(end 309.840122 -286.742886)
		(width 0.18288)
		(layer "In2.Cu")
		(net "M_B_CPU0_SA_DQS_DN<2>")
	)
	(segment
		(start 317.257684 -281.243024)
		(end 316.869826 -281.630882)
		(width 0.18288)
		(layer "In2.Cu")
		(net "M_B_CPU0_SA_DQS_DN<2>")
	)
	(segment
		(start 332.623414 -265.63828)
		(end 332.623668 -265.639042)
		(width 0.088646)
		(layer "In2.Cu")
		(net "M_B_CPU0_SA_DQS_DN<2>")
	)
	(segment
		(start 306.997608 -290.044124)
		(end 306.763674 -290.607496)
		(width 0.18288)
		(layer "In2.Cu")
		(net "M_B_CPU0_SA_DQS_DN<2>")
	)
	(segment
		(start 302.068992 -294.604948)
		(end 301.95393 -294.72001)
		(width 0.18288)
		(layer "In2.Cu")
		(net "M_B_CPU0_SA_DQS_DN<2>")
	)
	(segment
		(start 314.702698 -283.79801)
		(end 314.33516 -283.79801)
		(width 0.18288)
		(layer "In2.Cu")
		(net "M_B_CPU0_SA_DQS_DN<2>")
	)
	(segment
		(start 302.313086 -294.360854)
		(end 302.313086 -294.37711)
		(width 0.16002)
		(layer "In2.Cu")
		(net "M_B_CPU0_SA_DQS_DN<2>")
	)
	(segment
		(start 320.454528 -276.530308)
		(end 320.454528 -276.70633)
		(width 0.18288)
		(layer "In2.Cu")
		(net "M_B_CPU0_SA_DQS_DN<2>")
	)
	(segment
		(start 297.253914 -293.86657)
		(end 297.05427 -293.666926)
		(width 0.16002)
		(layer "In2.Cu")
		(net "M_B_CPU0_SA_DQS_DN<2>")
	)
	(segment
		(start 308.01818 -287.585658)
		(end 308.01818 -287.601406)
		(width 0.16002)
		(layer "In2.Cu")
		(net "M_B_CPU0_SA_DQS_DN<2>")
	)
	(segment
		(start 306.763674 -290.607496)
		(end 306.337208 -291.03447)
		(width 0.18288)
		(layer "In2.Cu")
		(net "M_B_CPU0_SA_DQS_DN<2>")
	)
	(segment
		(start 302.701706 -293.706042)
		(end 302.701706 -293.972234)
		(width 0.18288)
		(layer "In2.Cu")
		(net "M_B_CPU0_SA_DQS_DN<2>")
	)
	(segment
		(start 331.492606 -265.899138)
		(end 330.487274 -266.904724)
		(width 0.088646)
		(layer "In2.Cu")
		(net "M_B_CPU0_SA_DQS_DN<2>")
	)
	(segment
		(start 297.27017 -293.86657)
		(end 297.253914 -293.86657)
		(width 0.16002)
		(layer "In2.Cu")
		(net "M_B_CPU0_SA_DQS_DN<2>")
	)
	(segment
		(start 313.94019 -284.19298)
		(end 313.911996 -284.221174)
		(width 0.16002)
		(layer "In2.Cu")
		(net "M_B_CPU0_SA_DQS_DN<2>")
	)
	(segment
		(start 297.026076 -293.622476)
		(end 296.78249 -293.37889)
		(width 0.18288)
		(layer "In2.Cu")
		(net "M_B_CPU0_SA_DQS_DN<2>")
	)
	(segment
		(start 323.310504 -273.850354)
		(end 322.922646 -274.238212)
		(width 0.18288)
		(layer "In2.Cu")
		(net "M_B_CPU0_SA_DQS_DN<2>")
	)
	(segment
		(start 306.997608 -288.91484)
		(end 306.997608 -290.044124)
		(width 0.18288)
		(layer "In2.Cu")
		(net "M_B_CPU0_SA_DQS_DN<2>")
	)
	(segment
		(start 321.018662 -276.142196)
		(end 320.84264 -276.142196)
		(width 0.18288)
		(layer "In2.Cu")
		(net "M_B_CPU0_SA_DQS_DN<2>")
	)
	(segment
		(start 323.698616 -273.28622)
		(end 323.310504 -273.674332)
		(width 0.18288)
		(layer "In2.Cu")
		(net "M_B_CPU0_SA_DQS_DN<2>")
	)
	(segment
		(start 328.226928 -268.93393)
		(end 327.682606 -269.478252)
		(width 0.18288)
		(layer "In2.Cu")
		(net "M_B_CPU0_SA_DQS_DN<2>")
	)
	(segment
		(start 321.40652 -275.578316)
		(end 321.40652 -275.754338)
		(width 0.18288)
		(layer "In2.Cu")
		(net "M_B_CPU0_SA_DQS_DN<2>")
	)
	(segment
		(start 326.16648 -270.994378)
		(end 325.778622 -271.382236)
		(width 0.18288)
		(layer "In2.Cu")
		(net "M_B_CPU0_SA_DQS_DN<2>")
	)
	(segment
		(start 324.82663 -272.334228)
		(end 324.650608 -272.334228)
		(width 0.18288)
		(layer "In2.Cu")
		(net "M_B_CPU0_SA_DQS_DN<2>")
	)
	(segment
		(start 304.254408 -292.15334)
		(end 304.226214 -292.181534)
		(width 0.16002)
		(layer "In2.Cu")
		(net "M_B_CPU0_SA_DQS_DN<2>")
	)
	(segment
		(start 324.262496 -272.898362)
		(end 323.874638 -273.28622)
		(width 0.18288)
		(layer "In2.Cu")
		(net "M_B_CPU0_SA_DQS_DN<2>")
	)
	(segment
		(start 325.778622 -271.382236)
		(end 325.6026 -271.382236)
		(width 0.18288)
		(layer "In2.Cu")
		(net "M_B_CPU0_SA_DQS_DN<2>")
	)
	(segment
		(start 307.216556 -288.387536)
		(end 306.997608 -288.91484)
		(width 0.18288)
		(layer "In2.Cu")
		(net "M_B_CPU0_SA_DQS_DN<2>")
	)
	(segment
		(start 327.118472 -269.866364)
		(end 327.118472 -270.042386)
		(width 0.18288)
		(layer "In2.Cu")
		(net "M_B_CPU0_SA_DQS_DN<2>")
	)
	(segment
		(start 304.470308 -291.953188)
		(end 304.270156 -292.15334)
		(width 0.16002)
		(layer "In2.Cu")
		(net "M_B_CPU0_SA_DQS_DN<2>")
	)
	(segment
		(start 306.093114 -291.278564)
		(end 306.06492 -291.306758)
		(width 0.16002)
		(layer "In2.Cu")
		(net "M_B_CPU0_SA_DQS_DN<2>")
	)
	(segment
		(start 316.305692 -282.195016)
		(end 314.702698 -283.79801)
		(width 0.18288)
		(layer "In2.Cu")
		(net "M_B_CPU0_SA_DQS_DN<2>")
	)
	(segment
		(start 324.650608 -272.334228)
		(end 324.262496 -272.72234)
		(width 0.18288)
		(layer "In2.Cu")
		(net "M_B_CPU0_SA_DQS_DN<2>")
	)
	(segment
		(start 296.78249 -293.37889)
		(end 296.199306 -293.37889)
		(width 0.18288)
		(layer "In2.Cu")
		(net "M_B_CPU0_SA_DQS_DN<2>")
	)
	(segment
		(start 304.270156 -292.15334)
		(end 304.254408 -292.15334)
		(width 0.16002)
		(layer "In2.Cu")
		(net "M_B_CPU0_SA_DQS_DN<2>")
	)
	(segment
		(start 322.746624 -274.238212)
		(end 322.358512 -274.626324)
		(width 0.18288)
		(layer "In2.Cu")
		(net "M_B_CPU0_SA_DQS_DN<2>")
	)
	(segment
		(start 307.80228 -287.801558)
		(end 307.774086 -287.829752)
		(width 0.16002)
		(layer "In2.Cu")
		(net "M_B_CPU0_SA_DQS_DN<2>")
	)
	(segment
		(start 311.843166 -285.293054)
		(end 311.814972 -285.321248)
		(width 0.16002)
		(layer "In2.Cu")
		(net "M_B_CPU0_SA_DQS_DN<2>")
	)
	(segment
		(start 325.214488 -271.94637)
		(end 324.82663 -272.334228)
		(width 0.18288)
		(layer "In2.Cu")
		(net "M_B_CPU0_SA_DQS_DN<2>")
	)
	(segment
		(start 308.046374 -287.557464)
		(end 308.01818 -287.585658)
		(width 0.16002)
		(layer "In2.Cu")
		(net "M_B_CPU0_SA_DQS_DN<2>")
	)
	(segment
		(start 317.822072 -280.678636)
		(end 317.64605 -280.678636)
		(width 0.18288)
		(layer "In2.Cu")
		(net "M_B_CPU0_SA_DQS_DN<2>")
	)
	(segment
		(start 307.774086 -287.829752)
		(end 307.216556 -288.387536)
		(width 0.18288)
		(layer "In2.Cu")
		(net "M_B_CPU0_SA_DQS_DN<2>")
	)
	(segment
		(start 313.911996 -284.221174)
		(end 313.911996 -284.23743)
		(width 0.16002)
		(layer "In2.Cu")
		(net "M_B_CPU0_SA_DQS_DN<2>")
	)
	(segment
		(start 309.811928 -286.787336)
		(end 309.612284 -286.98698)
		(width 0.16002)
		(layer "In2.Cu")
		(net "M_B_CPU0_SA_DQS_DN<2>")
	)
	(segment
		(start 309.254398 -287.32861)
		(end 308.275228 -287.32861)
		(width 0.18288)
		(layer "In2.Cu")
		(net "M_B_CPU0_SA_DQS_DN<2>")
	)
	(segment
		(start 306.10937 -291.278564)
		(end 306.093114 -291.278564)
		(width 0.16002)
		(layer "In2.Cu")
		(net "M_B_CPU0_SA_DQS_DN<2>")
	)
	(segment
		(start 309.567834 -287.015174)
		(end 309.254398 -287.32861)
		(width 0.18288)
		(layer "In2.Cu")
		(net "M_B_CPU0_SA_DQS_DN<2>")
	)
	(segment
		(start 302.34128 -294.33266)
		(end 302.313086 -294.360854)
		(width 0.16002)
		(layer "In2.Cu")
		(net "M_B_CPU0_SA_DQS_DN<2>")
	)
	(segment
		(start 306.330096 -291.03447)
		(end 306.305458 -291.059108)
		(width 0.16002)
		(layer "In2.Cu")
		(net "M_B_CPU0_SA_DQS_DN<2>")
	)
	(segment
		(start 312.059066 -285.092902)
		(end 311.858914 -285.293054)
		(width 0.16002)
		(layer "In2.Cu")
		(net "M_B_CPU0_SA_DQS_DN<2>")
	)
	(segment
		(start 308.01818 -287.601406)
		(end 307.818028 -287.801558)
		(width 0.16002)
		(layer "In2.Cu")
		(net "M_B_CPU0_SA_DQS_DN<2>")
	)
	(segment
		(start 299.564298 -294.057832)
		(end 299.298106 -293.79164)
		(width 0.18288)
		(layer "In2.Cu")
		(net "M_B_CPU0_SA_DQS_DN<2>")
	)
	(segment
		(start 316.693804 -281.630882)
		(end 316.305692 -282.018994)
		(width 0.18288)
		(layer "In2.Cu")
		(net "M_B_CPU0_SA_DQS_DN<2>")
	)
	(segment
		(start 308.275228 -287.32861)
		(end 308.046374 -287.557464)
		(width 0.18288)
		(layer "In2.Cu")
		(net "M_B_CPU0_SA_DQS_DN<2>")
	)
	(segment
		(start 313.473338 -284.659832)
		(end 312.476388 -284.659832)
		(width 0.18288)
		(layer "In2.Cu")
		(net "M_B_CPU0_SA_DQS_DN<2>")
	)
	(segment
		(start 309.612284 -286.98698)
		(end 309.596028 -286.98698)
		(width 0.16002)
		(layer "In2.Cu")
		(net "M_B_CPU0_SA_DQS_DN<2>")
	)
	(segment
		(start 305.760628 -291.61105)
		(end 304.796698 -291.61105)
		(width 0.18288)
		(layer "In2.Cu")
		(net "M_B_CPU0_SA_DQS_DN<2>")
	)
	(segment
		(start 300.589442 -294.576754)
		(end 300.573186 -294.576754)
		(width 0.16002)
		(layer "In2.Cu")
		(net "M_B_CPU0_SA_DQS_DN<2>")
	)
	(segment
		(start 331.856588 -265.690858)
		(end 331.612748 -265.812524)
		(width 0.088646)
		(layer "In2.Cu")
		(net "M_B_CPU0_SA_DQS_DN<2>")
	)
	(segment
		(start 319.890648 -277.094188)
		(end 319.502536 -277.4823)
		(width 0.18288)
		(layer "In2.Cu")
		(net "M_B_CPU0_SA_DQS_DN<2>")
	)
	(segment
		(start 312.476388 -284.659832)
		(end 312.08726 -285.04896)
		(width 0.18288)
		(layer "In2.Cu")
		(net "M_B_CPU0_SA_DQS_DN<2>")
	)
	(segment
		(start 309.596028 -286.98698)
		(end 309.567834 -287.015174)
		(width 0.16002)
		(layer "In2.Cu")
		(net "M_B_CPU0_SA_DQS_DN<2>")
	)
	(segment
		(start 314.33516 -283.79801)
		(end 313.94019 -284.19298)
		(width 0.18288)
		(layer "In2.Cu")
		(net "M_B_CPU0_SA_DQS_DN<2>")
	)
	(segment
		(start 298.528232 -294.064436)
		(end 297.468036 -294.064436)
		(width 0.18288)
		(layer "In2.Cu")
		(net "M_B_CPU0_SA_DQS_DN<2>")
	)
	(segment
		(start 297.298364 -293.894764)
		(end 297.27017 -293.86657)
		(width 0.16002)
		(layer "In2.Cu")
		(net "M_B_CPU0_SA_DQS_DN<2>")
	)
	(segment
		(start 304.226214 -292.181534)
		(end 302.701706 -293.706042)
		(width 0.18288)
		(layer "In2.Cu")
		(net "M_B_CPU0_SA_DQS_DN<2>")
	)
	(segment
		(start 323.310504 -273.674332)
		(end 323.310504 -273.850354)
		(width 0.18288)
		(layer "In2.Cu")
		(net "M_B_CPU0_SA_DQS_DN<2>")
	)
	(segment
		(start 309.840122 -286.742886)
		(end 309.811928 -286.77108)
		(width 0.16002)
		(layer "In2.Cu")
		(net "M_B_CPU0_SA_DQS_DN<2>")
	)
	(segment
		(start 319.502536 -277.4823)
		(end 319.502536 -277.658322)
		(width 0.18288)
		(layer "In2.Cu")
		(net "M_B_CPU0_SA_DQS_DN<2>")
	)
	(segment
		(start 324.262496 -272.72234)
		(end 324.262496 -272.898362)
		(width 0.18288)
		(layer "In2.Cu")
		(net "M_B_CPU0_SA_DQS_DN<2>")
	)
	(segment
		(start 307.818028 -287.801558)
		(end 307.80228 -287.801558)
		(width 0.16002)
		(layer "In2.Cu")
		(net "M_B_CPU0_SA_DQS_DN<2>")
	)
	(segment
		(start 298.801028 -293.79164)
		(end 298.528232 -294.064436)
		(width 0.18288)
		(layer "In2.Cu")
		(net "M_B_CPU0_SA_DQS_DN<2>")
	)
	(segment
		(start 330.487274 -266.904724)
		(end 330.402946 -266.904724)
		(width 0.088646)
		(layer "In2.Cu")
		(net "M_B_CPU0_SA_DQS_DN<2>")
	)
	(segment
		(start 327.118472 -270.042386)
		(end 326.730614 -270.430244)
		(width 0.18288)
		(layer "In2.Cu")
		(net "M_B_CPU0_SA_DQS_DN<2>")
	)
	(segment
		(start 302.097186 -294.576754)
		(end 302.068992 -294.604948)
		(width 0.16002)
		(layer "In2.Cu")
		(net "M_B_CPU0_SA_DQS_DN<2>")
	)
	(segment
		(start 311.858914 -285.293054)
		(end 311.843166 -285.293054)
		(width 0.16002)
		(layer "In2.Cu")
		(net "M_B_CPU0_SA_DQS_DN<2>")
	)
	(segment
		(start 312.059066 -285.077154)
		(end 312.059066 -285.092902)
		(width 0.16002)
		(layer "In2.Cu")
		(net "M_B_CPU0_SA_DQS_DN<2>")
	)
	(segment
		(start 313.667902 -284.465268)
		(end 313.473338 -284.659832)
		(width 0.18288)
		(layer "In2.Cu")
		(net "M_B_CPU0_SA_DQS_DN<2>")
	)
	(segment
		(start 322.922646 -274.238212)
		(end 322.746624 -274.238212)
		(width 0.18288)
		(layer "In2.Cu")
		(net "M_B_CPU0_SA_DQS_DN<2>")
	)
	(segment
		(start 301.95393 -294.72001)
		(end 300.732698 -294.72001)
		(width 0.18288)
		(layer "In2.Cu")
		(net "M_B_CPU0_SA_DQS_DN<2>")
	)
	(segment
		(start 316.869826 -281.630882)
		(end 316.693804 -281.630882)
		(width 0.18288)
		(layer "In2.Cu")
		(net "M_B_CPU0_SA_DQS_DN<2>")
	)
	(segment
		(start 317.257684 -281.067002)
		(end 317.257684 -281.243024)
		(width 0.18288)
		(layer "In2.Cu")
		(net "M_B_CPU0_SA_DQS_DN<2>")
	)
	(segment
		(start 326.16648 -270.818356)
		(end 326.16648 -270.994378)
		(width 0.18288)
		(layer "In2.Cu")
		(net "M_B_CPU0_SA_DQS_DN<2>")
	)
	(segment
		(start 320.454528 -276.70633)
		(end 320.06667 -277.094188)
		(width 0.18288)
		(layer "In2.Cu")
		(net "M_B_CPU0_SA_DQS_DN<2>")
	)
	(segment
		(start 326.554592 -270.430244)
		(end 326.16648 -270.818356)
		(width 0.18288)
		(layer "In2.Cu")
		(net "M_B_CPU0_SA_DQS_DN<2>")
	)
	(segment
		(start 295.548558 -293.648384)
		(end 295.1861 -293.648384)
		(width 0.18288)
		(layer "In2.Cu")
		(net "M_B_CPU0_SA_DQS_DN<2>")
	)
	(segment
		(start 302.313086 -294.37711)
		(end 302.113442 -294.576754)
		(width 0.16002)
		(layer "In2.Cu")
		(net "M_B_CPU0_SA_DQS_DN<2>")
	)
	(segment
		(start 336.195162 -265.314176)
		(end 336.155792 -265.314176)
		(width 0.088646)
		(layer "In2.Cu")
		(net "M_B_CPU0_SA_DQS_DN<2>")
	)
	(segment
		(start 302.113442 -294.576754)
		(end 302.097186 -294.576754)
		(width 0.16002)
		(layer "In2.Cu")
		(net "M_B_CPU0_SA_DQS_DN<2>")
	)
	(segment
		(start 317.64605 -280.678636)
		(end 317.257684 -281.067002)
		(width 0.18288)
		(layer "In2.Cu")
		(net "M_B_CPU0_SA_DQS_DN<2>")
	)
	(segment
		(start 320.84264 -276.142196)
		(end 320.454528 -276.530308)
		(width 0.18288)
		(layer "In2.Cu")
		(net "M_B_CPU0_SA_DQS_DN<2>")
	)
	(segment
		(start 321.794632 -275.190204)
		(end 321.40652 -275.578316)
		(width 0.18288)
		(layer "In2.Cu")
		(net "M_B_CPU0_SA_DQS_DN<2>")
	)
	(segment
		(start 326.730614 -270.430244)
		(end 326.554592 -270.430244)
		(width 0.18288)
		(layer "In2.Cu")
		(net "M_B_CPU0_SA_DQS_DN<2>")
	)
	(segment
		(start 327.682606 -269.478252)
		(end 327.506584 -269.478252)
		(width 0.18288)
		(layer "In2.Cu")
		(net "M_B_CPU0_SA_DQS_DN<2>")
	)
	(segment
		(start 311.06745 -286.06877)
		(end 310.514238 -286.06877)
		(width 0.18288)
		(layer "In2.Cu")
		(net "M_B_CPU0_SA_DQS_DN<2>")
	)
	(segment
		(start 325.6026 -271.382236)
		(end 325.214488 -271.770348)
		(width 0.18288)
		(layer "In2.Cu")
		(net "M_B_CPU0_SA_DQS_DN<2>")
	)
	(segment
		(start 300.345348 -294.33266)
		(end 300.07052 -294.057832)
		(width 0.18288)
		(layer "In2.Cu")
		(net "M_B_CPU0_SA_DQS_DN<2>")
	)
	(segment
		(start 320.06667 -277.094188)
		(end 319.890648 -277.094188)
		(width 0.18288)
		(layer "In2.Cu")
		(net "M_B_CPU0_SA_DQS_DN<2>")
	)
	(segment
		(start 312.08726 -285.04896)
		(end 312.059066 -285.077154)
		(width 0.16002)
		(layer "In2.Cu")
		(net "M_B_CPU0_SA_DQS_DN<2>")
	)
	(segment
		(start 300.373542 -294.360854)
		(end 300.345348 -294.33266)
		(width 0.16002)
		(layer "In2.Cu")
		(net "M_B_CPU0_SA_DQS_DN<2>")
	)
	(segment
		(start 313.696096 -284.437074)
		(end 313.667902 -284.465268)
		(width 0.16002)
		(layer "In2.Cu")
		(net "M_B_CPU0_SA_DQS_DN<2>")
	)
	(segment
		(start 297.05427 -293.65067)
		(end 297.026076 -293.622476)
		(width 0.16002)
		(layer "In2.Cu")
		(net "M_B_CPU0_SA_DQS_DN<2>")
	)
	(segment
		(start 330.402946 -266.904724)
		(end 328.477118 -268.830298)
		(width 0.18288)
		(layer "In2.Cu")
		(net "M_B_CPU0_SA_DQS_DN<2>")
	)
	(segment
		(start 309.811928 -286.77108)
		(end 309.811928 -286.787336)
		(width 0.16002)
		(layer "In2.Cu")
		(net "M_B_CPU0_SA_DQS_DN<2>")
	)
	(segment
		(start 300.373542 -294.37711)
		(end 300.373542 -294.360854)
		(width 0.16002)
		(layer "In2.Cu")
		(net "M_B_CPU0_SA_DQS_DN<2>")
	)
	(segment
		(start 296.199306 -293.37889)
		(end 295.548558 -293.648384)
		(width 0.18288)
		(layer "In2.Cu")
		(net "M_B_CPU0_SA_DQS_DN<2>")
	)
	(segment
		(start 304.796698 -291.61105)
		(end 304.498502 -291.909246)
		(width 0.18288)
		(layer "In2.Cu")
		(net "M_B_CPU0_SA_DQS_DN<2>")
	)
	(segment
		(start 306.337208 -291.03447)
		(end 306.330096 -291.03447)
		(width 0.16002)
		(layer "In2.Cu")
		(net "M_B_CPU0_SA_DQS_DN<2>")
	)
	(segment
		(start 322.358512 -274.802346)
		(end 321.970654 -275.190204)
		(width 0.18288)
		(layer "In2.Cu")
		(net "M_B_CPU0_SA_DQS_DN<2>")
	)
	(segment
		(start 321.40652 -275.754338)
		(end 321.018662 -276.142196)
		(width 0.18288)
		(layer "In2.Cu")
		(net "M_B_CPU0_SA_DQS_DN<2>")
	)
	(arc
		(start 334.50276 -265.638534)
		(mid 334.315562 -265.688677)
		(end 334.128364 -265.638534)
		(width 0.088646)
		(layer "In2.Cu")
		(net "M_B_CPU0_SA_DQS_DN<2>")
	)
	(arc
		(start 332.623668 -265.639042)
		(mid 332.468377 -265.688107)
		(end 332.30693 -265.666728)
		(width 0.088646)
		(layer "In2.Cu")
		(net "M_B_CPU0_SA_DQS_DN<2>")
	)
	(arc
		(start 334.128364 -265.638534)
		(mid 333.845662 -265.562792)
		(end 333.56296 -265.638534)
		(width 0.088646)
		(layer "In2.Cu")
		(net "M_B_CPU0_SA_DQS_DN<2>")
	)
	(arc
		(start 331.983842 -265.645392)
		(mid 331.918826 -265.664235)
		(end 331.856588 -265.690858)
		(width 0.088646)
		(layer "In2.Cu")
		(net "M_B_CPU0_SA_DQS_DN<2>")
	)
	(arc
		(start 331.612748 -265.812524)
		(mid 331.549225 -265.851041)
		(end 331.492606 -265.899138)
		(width 0.088646)
		(layer "In2.Cu")
		(net "M_B_CPU0_SA_DQS_DN<2>")
	)
	(arc
		(start 335.068164 -265.638534)
		(mid 334.785462 -265.562792)
		(end 334.50276 -265.638534)
		(width 0.088646)
		(layer "In2.Cu")
		(net "M_B_CPU0_SA_DQS_DN<2>")
	)
	(arc
		(start 332.30693 -265.666728)
		(mid 332.146919 -265.632896)
		(end 331.983842 -265.645392)
		(width 0.088646)
		(layer "In2.Cu")
		(net "M_B_CPU0_SA_DQS_DN<2>")
	)
	(arc
		(start 333.188564 -265.638534)
		(mid 332.906035 -265.562792)
		(end 332.623414 -265.63828)
		(width 0.088646)
		(layer "In2.Cu")
		(net "M_B_CPU0_SA_DQS_DN<2>")
	)
	(arc
		(start 333.56296 -265.638534)
		(mid 333.375762 -265.688677)
		(end 333.188564 -265.638534)
		(width 0.088646)
		(layer "In2.Cu")
		(net "M_B_CPU0_SA_DQS_DN<2>")
	)
	(arc
		(start 335.442306 -265.638534)
		(mid 335.255252 -265.68855)
		(end 335.068164 -265.638534)
		(width 0.088646)
		(layer "In2.Cu")
		(net "M_B_CPU0_SA_DQS_DN<2>")
	)
	(arc
		(start 335.973928 -265.49604)
		(mid 335.698729 -265.532272)
		(end 335.442306 -265.638534)
		(width 0.088646)
		(layer "In2.Cu")
		(net "M_B_CPU0_SA_DQS_DN<2>")
	)
	(segment
		(start 339.484716 -272.639028)
		(end 339.484462 -272.639282)
		(width 0.20066)
		(layer "F.Cu")
		(net "M_B_CPU0_SA_DQS_DN<1>")
	)
	(segment
		(start 291.711888 -303.141634)
		(end 291.556694 -303.141634)
		(width 0.20066)
		(layer "F.Cu")
		(net "M_B_CPU0_SA_DQS_DN<1>")
	)
	(segment
		(start 288.755328 -303.403)
		(end 288.215324 -303.403)
		(width 0.20066)
		(layer "F.Cu")
		(net "M_B_CPU0_SA_DQS_DN<1>")
	)
	(segment
		(start 293.252906 -302.716692)
		(end 292.991794 -302.977804)
		(width 0.20066)
		(layer "F.Cu")
		(net "M_B_CPU0_SA_DQS_DN<1>")
	)
	(segment
		(start 293.799514 -302.716692)
		(end 293.252906 -302.716692)
		(width 0.20066)
		(layer "F.Cu")
		(net "M_B_CPU0_SA_DQS_DN<1>")
	)
	(segment
		(start 287.579308 -302.977804)
		(end 287.065466 -302.977804)
		(width 0.20066)
		(layer "F.Cu")
		(net "M_B_CPU0_SA_DQS_DN<1>")
	)
	(segment
		(start 289.23234 -303.130966)
		(end 289.231578 -303.130966)
		(width 0.101854)
		(layer "F.Cu")
		(net "M_B_CPU0_SA_DQS_DN<1>")
	)
	(segment
		(start 292.159944 -303.403)
		(end 291.973254 -303.403)
		(width 0.20066)
		(layer "F.Cu")
		(net "M_B_CPU0_SA_DQS_DN<1>")
	)
	(segment
		(start 286.804354 -302.716692)
		(end 286.255714 -302.716692)
		(width 0.20066)
		(layer "F.Cu")
		(net "M_B_CPU0_SA_DQS_DN<1>")
	)
	(segment
		(start 291.973254 -303.403)
		(end 291.711888 -303.141634)
		(width 0.20066)
		(layer "F.Cu")
		(net "M_B_CPU0_SA_DQS_DN<1>")
	)
	(segment
		(start 288.215324 -303.403)
		(end 287.579308 -302.977804)
		(width 0.20066)
		(layer "F.Cu")
		(net "M_B_CPU0_SA_DQS_DN<1>")
	)
	(segment
		(start 339.484716 -272.103342)
		(end 339.484716 -272.639028)
		(width 0.20066)
		(layer "F.Cu")
		(net "M_B_CPU0_SA_DQS_DN<1>")
	)
	(segment
		(start 289.027362 -303.130966)
		(end 288.755328 -303.403)
		(width 0.20066)
		(layer "F.Cu")
		(net "M_B_CPU0_SA_DQS_DN<1>")
	)
	(segment
		(start 292.991794 -302.977804)
		(end 292.58514 -302.977804)
		(width 0.20066)
		(layer "F.Cu")
		(net "M_B_CPU0_SA_DQS_DN<1>")
	)
	(segment
		(start 289.231578 -303.130966)
		(end 289.027362 -303.130966)
		(width 0.20066)
		(layer "F.Cu")
		(net "M_B_CPU0_SA_DQS_DN<1>")
	)
	(segment
		(start 294.904414 -302.716692)
		(end 293.799514 -302.716692)
		(width 0.20066)
		(layer "F.Cu")
		(net "M_B_CPU0_SA_DQS_DN<1>")
	)
	(segment
		(start 291.556694 -303.141634)
		(end 289.243008 -303.141634)
		(width 0.1016)
		(layer "F.Cu")
		(net "M_B_CPU0_SA_DQS_DN<1>")
	)
	(segment
		(start 289.243008 -303.141634)
		(end 289.23234 -303.130966)
		(width 0.101854)
		(layer "F.Cu")
		(net "M_B_CPU0_SA_DQS_DN<1>")
	)
	(segment
		(start 292.58514 -302.977804)
		(end 292.159944 -303.403)
		(width 0.20066)
		(layer "F.Cu")
		(net "M_B_CPU0_SA_DQS_DN<1>")
	)
	(segment
		(start 287.065466 -302.977804)
		(end 286.804354 -302.716692)
		(width 0.20066)
		(layer "F.Cu")
		(net "M_B_CPU0_SA_DQS_DN<1>")
	)
	(segment
		(start 313.890914 -298.891706)
		(end 313.638184 -299.144436)
		(width 0.18288)
		(layer "In4.Cu")
		(net "M_B_CPU0_SA_DQS_DN<1>")
	)
	(segment
		(start 295.87317 -302.724312)
		(end 295.621964 -302.975518)
		(width 0.18288)
		(layer "In4.Cu")
		(net "M_B_CPU0_SA_DQS_DN<1>")
	)
	(segment
		(start 327.705212 -281.25293)
		(end 327.316592 -281.640788)
		(width 0.18288)
		(layer "In4.Cu")
		(net "M_B_CPU0_SA_DQS_DN<1>")
	)
	(segment
		(start 322.5038 -289.527488)
		(end 322.571364 -289.689794)
		(width 0.18288)
		(layer "In4.Cu")
		(net "M_B_CPU0_SA_DQS_DN<1>")
	)
	(segment
		(start 326.927972 -282.20416)
		(end 326.75195 -282.203906)
		(width 0.18288)
		(layer "In4.Cu")
		(net "M_B_CPU0_SA_DQS_DN<1>")
	)
	(segment
		(start 314.539122 -299.128942)
		(end 314.301886 -298.891706)
		(width 0.18288)
		(layer "In4.Cu")
		(net "M_B_CPU0_SA_DQS_DN<1>")
	)
	(segment
		(start 322.571364 -289.689794)
		(end 322.362576 -290.197032)
		(width 0.18288)
		(layer "In4.Cu")
		(net "M_B_CPU0_SA_DQS_DN<1>")
	)
	(segment
		(start 313.638184 -299.144436)
		(end 312.908442 -299.144436)
		(width 0.18288)
		(layer "In4.Cu")
		(net "M_B_CPU0_SA_DQS_DN<1>")
	)
	(segment
		(start 328.658474 -280.302208)
		(end 328.269854 -280.690066)
		(width 0.18288)
		(layer "In4.Cu")
		(net "M_B_CPU0_SA_DQS_DN<1>")
	)
	(segment
		(start 323.08419 -288.44494)
		(end 322.875402 -288.952178)
		(width 0.18288)
		(layer "In4.Cu")
		(net "M_B_CPU0_SA_DQS_DN<1>")
	)
	(segment
		(start 335.922874 -272.957544)
		(end 335.91246 -272.96364)
		(width 0.088646)
		(layer "In4.Cu")
		(net "M_B_CPU0_SA_DQS_DN<1>")
	)
	(segment
		(start 338.985606 -272.818098)
		(end 338.732368 -272.963894)
		(width 0.088646)
		(layer "In4.Cu")
		(net "M_B_CPU0_SA_DQS_DN<1>")
	)
	(segment
		(start 326.363076 -282.767786)
		(end 325.97471 -283.155136)
		(width 0.18288)
		(layer "In4.Cu")
		(net "M_B_CPU0_SA_DQS_DN<1>")
	)
	(segment
		(start 323.016626 -288.28238)
		(end 323.08419 -288.44494)
		(width 0.18288)
		(layer "In4.Cu")
		(net "M_B_CPU0_SA_DQS_DN<1>")
	)
	(segment
		(start 332.868778 -276.415246)
		(end 332.868778 -276.894036)
		(width 0.088646)
		(layer "In4.Cu")
		(net "M_B_CPU0_SA_DQS_DN<1>")
	)
	(segment
		(start 325.409814 -283.719016)
		(end 324.766432 -284.360874)
		(width 0.18288)
		(layer "In4.Cu")
		(net "M_B_CPU0_SA_DQS_DN<1>")
	)
	(segment
		(start 330.620624 -278.517858)
		(end 330.44638 -278.517604)
		(width 0.18288)
		(layer "In4.Cu")
		(net "M_B_CPU0_SA_DQS_DN<1>")
	)
	(segment
		(start 330.961492 -278.177244)
		(end 330.620624 -278.517858)
		(width 0.18288)
		(layer "In4.Cu")
		(net "M_B_CPU0_SA_DQS_DN<1>")
	)
	(segment
		(start 327.881234 -281.253184)
		(end 327.705212 -281.25293)
		(width 0.18288)
		(layer "In4.Cu")
		(net "M_B_CPU0_SA_DQS_DN<1>")
	)
	(segment
		(start 327.316338 -281.81681)
		(end 326.927972 -282.20416)
		(width 0.18288)
		(layer "In4.Cu")
		(net "M_B_CPU0_SA_DQS_DN<1>")
	)
	(segment
		(start 325.409814 -283.718508)
		(end 325.409814 -283.719016)
		(width 0.18288)
		(layer "In4.Cu")
		(net "M_B_CPU0_SA_DQS_DN<1>")
	)
	(segment
		(start 330.44638 -278.517604)
		(end 330.08697 -278.877014)
		(width 0.18288)
		(layer "In4.Cu")
		(net "M_B_CPU0_SA_DQS_DN<1>")
	)
	(segment
		(start 323.388228 -287.707324)
		(end 323.225414 -287.774888)
		(width 0.18288)
		(layer "In4.Cu")
		(net "M_B_CPU0_SA_DQS_DN<1>")
	)
	(segment
		(start 331.171296 -278.051768)
		(end 331.086968 -278.051768)
		(width 0.088646)
		(layer "In4.Cu")
		(net "M_B_CPU0_SA_DQS_DN<1>")
	)
	(segment
		(start 310.16575 -299.742098)
		(end 309.768748 -299.742098)
		(width 0.18288)
		(layer "In4.Cu")
		(net "M_B_CPU0_SA_DQS_DN<1>")
	)
	(segment
		(start 334.034384 -274.59051)
		(end 334.03286 -274.591272)
		(width 0.088646)
		(layer "In4.Cu")
		(net "M_B_CPU0_SA_DQS_DN<1>")
	)
	(segment
		(start 321.478402 -292.017196)
		(end 321.54622 -292.179502)
		(width 0.18288)
		(layer "In4.Cu")
		(net "M_B_CPU0_SA_DQS_DN<1>")
	)
	(segment
		(start 332.868778 -276.894036)
		(end 331.924914 -277.8379)
		(width 0.088646)
		(layer "In4.Cu")
		(net "M_B_CPU0_SA_DQS_DN<1>")
	)
	(segment
		(start 329.72756 -279.41016)
		(end 329.553316 -279.409906)
		(width 0.18288)
		(layer "In4.Cu")
		(net "M_B_CPU0_SA_DQS_DN<1>")
	)
	(segment
		(start 331.924914 -277.8379)
		(end 331.385418 -277.8379)
		(width 0.088646)
		(layer "In4.Cu")
		(net "M_B_CPU0_SA_DQS_DN<1>")
	)
	(segment
		(start 328.269854 -280.690066)
		(end 328.2696 -280.865834)
		(width 0.18288)
		(layer "In4.Cu")
		(net "M_B_CPU0_SA_DQS_DN<1>")
	)
	(segment
		(start 321.54622 -292.179502)
		(end 321.317112 -292.736016)
		(width 0.18288)
		(layer "In4.Cu")
		(net "M_B_CPU0_SA_DQS_DN<1>")
	)
	(segment
		(start 298.54652 -303.405286)
		(end 298.163488 -303.405286)
		(width 0.18288)
		(layer "In4.Cu")
		(net "M_B_CPU0_SA_DQS_DN<1>")
	)
	(segment
		(start 297.482514 -302.724312)
		(end 295.87317 -302.724312)
		(width 0.18288)
		(layer "In4.Cu")
		(net "M_B_CPU0_SA_DQS_DN<1>")
	)
	(segment
		(start 331.385418 -277.8379)
		(end 331.231494 -277.991824)
		(width 0.088646)
		(layer "In4.Cu")
		(net "M_B_CPU0_SA_DQS_DN<1>")
	)
	(segment
		(start 321.850004 -291.441886)
		(end 321.68719 -291.50945)
		(width 0.18288)
		(layer "In4.Cu")
		(net "M_B_CPU0_SA_DQS_DN<1>")
	)
	(segment
		(start 309.768748 -299.742098)
		(end 309.52313 -299.987716)
		(width 0.18288)
		(layer "In4.Cu")
		(net "M_B_CPU0_SA_DQS_DN<1>")
	)
	(segment
		(start 298.163488 -303.405286)
		(end 297.482514 -302.724312)
		(width 0.18288)
		(layer "In4.Cu")
		(net "M_B_CPU0_SA_DQS_DN<1>")
	)
	(segment
		(start 309.52313 -299.987716)
		(end 308.98973 -299.987716)
		(width 0.18288)
		(layer "In4.Cu")
		(net "M_B_CPU0_SA_DQS_DN<1>")
	)
	(segment
		(start 334.972914 -272.96364)
		(end 334.966818 -272.967196)
		(width 0.088646)
		(layer "In4.Cu")
		(net "M_B_CPU0_SA_DQS_DN<1>")
	)
	(segment
		(start 336.862928 -272.957544)
		(end 336.852514 -272.96364)
		(width 0.088646)
		(layer "In4.Cu")
		(net "M_B_CPU0_SA_DQS_DN<1>")
	)
	(segment
		(start 322.199762 -290.264596)
		(end 321.990974 -290.772342)
		(width 0.18288)
		(layer "In4.Cu")
		(net "M_B_CPU0_SA_DQS_DN<1>")
	)
	(segment
		(start 334.032098 -274.59178)
		(end 334.026764 -274.594828)
		(width 0.088646)
		(layer "In4.Cu")
		(net "M_B_CPU0_SA_DQS_DN<1>")
	)
	(segment
		(start 314.301886 -298.891706)
		(end 313.890914 -298.891706)
		(width 0.18288)
		(layer "In4.Cu")
		(net "M_B_CPU0_SA_DQS_DN<1>")
	)
	(segment
		(start 339.259164 -272.818098)
		(end 338.985606 -272.818098)
		(width 0.088646)
		(layer "In4.Cu")
		(net "M_B_CPU0_SA_DQS_DN<1>")
	)
	(segment
		(start 312.908442 -299.144436)
		(end 312.026046 -300.026832)
		(width 0.18288)
		(layer "In4.Cu")
		(net "M_B_CPU0_SA_DQS_DN<1>")
	)
	(segment
		(start 307.349144 -301.084742)
		(end 305.659282 -302.774604)
		(width 0.18288)
		(layer "In4.Cu")
		(net "M_B_CPU0_SA_DQS_DN<1>")
	)
	(segment
		(start 325.410068 -283.54274)
		(end 325.409814 -283.718508)
		(width 0.18288)
		(layer "In4.Cu")
		(net "M_B_CPU0_SA_DQS_DN<1>")
	)
	(segment
		(start 331.231494 -277.991824)
		(end 331.171296 -278.051768)
		(width 0.088646)
		(layer "In4.Cu")
		(net "M_B_CPU0_SA_DQS_DN<1>")
	)
	(segment
		(start 314.924186 -299.128942)
		(end 314.539122 -299.128942)
		(width 0.18288)
		(layer "In4.Cu")
		(net "M_B_CPU0_SA_DQS_DN<1>")
	)
	(segment
		(start 321.990974 -290.772342)
		(end 322.058792 -290.934648)
		(width 0.18288)
		(layer "In4.Cu")
		(net "M_B_CPU0_SA_DQS_DN<1>")
	)
	(segment
		(start 328.834496 -280.302462)
		(end 328.658474 -280.302208)
		(width 0.18288)
		(layer "In4.Cu")
		(net "M_B_CPU0_SA_DQS_DN<1>")
	)
	(segment
		(start 322.058792 -290.934648)
		(end 321.850004 -291.441886)
		(width 0.18288)
		(layer "In4.Cu")
		(net "M_B_CPU0_SA_DQS_DN<1>")
	)
	(segment
		(start 308.98973 -299.987716)
		(end 307.349144 -301.084742)
		(width 0.18288)
		(layer "In4.Cu")
		(net "M_B_CPU0_SA_DQS_DN<1>")
	)
	(segment
		(start 328.2696 -280.865834)
		(end 327.881234 -281.253184)
		(width 0.18288)
		(layer "In4.Cu")
		(net "M_B_CPU0_SA_DQS_DN<1>")
	)
	(segment
		(start 302.541432 -303.413668)
		(end 299.47743 -303.413668)
		(width 0.18288)
		(layer "In4.Cu")
		(net "M_B_CPU0_SA_DQS_DN<1>")
	)
	(segment
		(start 334.03286 -274.591272)
		(end 334.032098 -274.59178)
		(width 0.088646)
		(layer "In4.Cu")
		(net "M_B_CPU0_SA_DQS_DN<1>")
	)
	(segment
		(start 333.571596 -275.400008)
		(end 333.562706 -275.405088)
		(width 0.088646)
		(layer "In4.Cu")
		(net "M_B_CPU0_SA_DQS_DN<1>")
	)
	(segment
		(start 295.621964 -302.975518)
		(end 295.16324 -302.975518)
		(width 0.18288)
		(layer "In4.Cu")
		(net "M_B_CPU0_SA_DQS_DN<1>")
	)
	(segment
		(start 321.317112 -292.736016)
		(end 314.924186 -299.128942)
		(width 0.18288)
		(layer "In4.Cu")
		(net "M_B_CPU0_SA_DQS_DN<1>")
	)
	(segment
		(start 321.68719 -291.50945)
		(end 321.478402 -292.017196)
		(width 0.18288)
		(layer "In4.Cu")
		(net "M_B_CPU0_SA_DQS_DN<1>")
	)
	(segment
		(start 334.04175 -274.586192)
		(end 334.034384 -274.59051)
		(width 0.088646)
		(layer "In4.Cu")
		(net "M_B_CPU0_SA_DQS_DN<1>")
	)
	(segment
		(start 334.502252 -273.777964)
		(end 334.496918 -273.781012)
		(width 0.088646)
		(layer "In4.Cu")
		(net "M_B_CPU0_SA_DQS_DN<1>")
	)
	(segment
		(start 331.086968 -278.051768)
		(end 331.064616 -278.07412)
		(width 0.088646)
		(layer "In4.Cu")
		(net "M_B_CPU0_SA_DQS_DN<1>")
	)
	(segment
		(start 325.798688 -283.154882)
		(end 325.410068 -283.54274)
		(width 0.18288)
		(layer "In4.Cu")
		(net "M_B_CPU0_SA_DQS_DN<1>")
	)
	(segment
		(start 305.659282 -302.774604)
		(end 304.084482 -302.774604)
		(width 0.18288)
		(layer "In4.Cu")
		(net "M_B_CPU0_SA_DQS_DN<1>")
	)
	(segment
		(start 322.875402 -288.952178)
		(end 322.712588 -289.019742)
		(width 0.18288)
		(layer "In4.Cu")
		(net "M_B_CPU0_SA_DQS_DN<1>")
	)
	(segment
		(start 322.712588 -289.019742)
		(end 322.5038 -289.527488)
		(width 0.18288)
		(layer "In4.Cu")
		(net "M_B_CPU0_SA_DQS_DN<1>")
	)
	(segment
		(start 329.193906 -279.769316)
		(end 329.193652 -279.94356)
		(width 0.18288)
		(layer "In4.Cu")
		(net "M_B_CPU0_SA_DQS_DN<1>")
	)
	(segment
		(start 323.225414 -287.774888)
		(end 323.016626 -288.28238)
		(width 0.18288)
		(layer "In4.Cu")
		(net "M_B_CPU0_SA_DQS_DN<1>")
	)
	(segment
		(start 337.802474 -272.957544)
		(end 337.79206 -272.96364)
		(width 0.088646)
		(layer "In4.Cu")
		(net "M_B_CPU0_SA_DQS_DN<1>")
	)
	(segment
		(start 325.97471 -283.155136)
		(end 325.798688 -283.154882)
		(width 0.18288)
		(layer "In4.Cu")
		(net "M_B_CPU0_SA_DQS_DN<1>")
	)
	(segment
		(start 298.808902 -303.142904)
		(end 298.54652 -303.405286)
		(width 0.18288)
		(layer "In4.Cu")
		(net "M_B_CPU0_SA_DQS_DN<1>")
	)
	(segment
		(start 333.12227 -276.161754)
		(end 332.868778 -276.415246)
		(width 0.088646)
		(layer "In4.Cu")
		(net "M_B_CPU0_SA_DQS_DN<1>")
	)
	(segment
		(start 338.732368 -272.963894)
		(end 338.732114 -272.96364)
		(width 0.088646)
		(layer "In4.Cu")
		(net "M_B_CPU0_SA_DQS_DN<1>")
	)
	(segment
		(start 330.086716 -279.051258)
		(end 329.72756 -279.41016)
		(width 0.18288)
		(layer "In4.Cu")
		(net "M_B_CPU0_SA_DQS_DN<1>")
	)
	(segment
		(start 295.16324 -302.975518)
		(end 294.904414 -302.716692)
		(width 0.18288)
		(layer "In4.Cu")
		(net "M_B_CPU0_SA_DQS_DN<1>")
	)
	(segment
		(start 327.316592 -281.640788)
		(end 327.316338 -281.81681)
		(width 0.18288)
		(layer "In4.Cu")
		(net "M_B_CPU0_SA_DQS_DN<1>")
	)
	(segment
		(start 310.450484 -300.026832)
		(end 310.16575 -299.742098)
		(width 0.18288)
		(layer "In4.Cu")
		(net "M_B_CPU0_SA_DQS_DN<1>")
	)
	(segment
		(start 299.206666 -303.142904)
		(end 298.808902 -303.142904)
		(width 0.18288)
		(layer "In4.Cu")
		(net "M_B_CPU0_SA_DQS_DN<1>")
	)
	(segment
		(start 326.36333 -282.591764)
		(end 326.363076 -282.767786)
		(width 0.18288)
		(layer "In4.Cu")
		(net "M_B_CPU0_SA_DQS_DN<1>")
	)
	(segment
		(start 334.503014 -273.777456)
		(end 334.502252 -273.777964)
		(width 0.088646)
		(layer "In4.Cu")
		(net "M_B_CPU0_SA_DQS_DN<1>")
	)
	(segment
		(start 334.983328 -272.957544)
		(end 334.972914 -272.96364)
		(width 0.088646)
		(layer "In4.Cu")
		(net "M_B_CPU0_SA_DQS_DN<1>")
	)
	(segment
		(start 304.084482 -302.774604)
		(end 302.541432 -303.413668)
		(width 0.18288)
		(layer "In4.Cu")
		(net "M_B_CPU0_SA_DQS_DN<1>")
	)
	(segment
		(start 312.026046 -300.026832)
		(end 310.450484 -300.026832)
		(width 0.18288)
		(layer "In4.Cu")
		(net "M_B_CPU0_SA_DQS_DN<1>")
	)
	(segment
		(start 339.452712 -272.755106)
		(end 339.41385 -272.777204)
		(width 0.088646)
		(layer "In4.Cu")
		(net "M_B_CPU0_SA_DQS_DN<1>")
	)
	(segment
		(start 326.75195 -282.203906)
		(end 326.36333 -282.591764)
		(width 0.18288)
		(layer "In4.Cu")
		(net "M_B_CPU0_SA_DQS_DN<1>")
	)
	(segment
		(start 334.690212 -273.453098)
		(end 334.690212 -273.461734)
		(width 0.088646)
		(layer "In4.Cu")
		(net "M_B_CPU0_SA_DQS_DN<1>")
	)
	(segment
		(start 339.484462 -272.639282)
		(end 339.452712 -272.755106)
		(width 0.088646)
		(layer "In4.Cu")
		(net "M_B_CPU0_SA_DQS_DN<1>")
	)
	(segment
		(start 331.064616 -278.07412)
		(end 330.961492 -278.177244)
		(width 0.18288)
		(layer "In4.Cu")
		(net "M_B_CPU0_SA_DQS_DN<1>")
	)
	(segment
		(start 330.08697 -278.877014)
		(end 330.086716 -279.051258)
		(width 0.18288)
		(layer "In4.Cu")
		(net "M_B_CPU0_SA_DQS_DN<1>")
	)
	(segment
		(start 329.193652 -279.94356)
		(end 328.834496 -280.302462)
		(width 0.18288)
		(layer "In4.Cu")
		(net "M_B_CPU0_SA_DQS_DN<1>")
	)
	(segment
		(start 324.766432 -284.360874)
		(end 323.388228 -287.707324)
		(width 0.18288)
		(layer "In4.Cu")
		(net "M_B_CPU0_SA_DQS_DN<1>")
	)
	(segment
		(start 329.553316 -279.409906)
		(end 329.193906 -279.769316)
		(width 0.18288)
		(layer "In4.Cu")
		(net "M_B_CPU0_SA_DQS_DN<1>")
	)
	(segment
		(start 322.362576 -290.197032)
		(end 322.199762 -290.264596)
		(width 0.18288)
		(layer "In4.Cu")
		(net "M_B_CPU0_SA_DQS_DN<1>")
	)
	(segment
		(start 299.47743 -303.413668)
		(end 299.206666 -303.142904)
		(width 0.18288)
		(layer "In4.Cu")
		(net "M_B_CPU0_SA_DQS_DN<1>")
	)
	(arc
		(start 334.220312 -274.266914)
		(mid 334.172633 -274.449814)
		(end 334.04175 -274.586192)
		(width 0.088646)
		(layer "In4.Cu")
		(net "M_B_CPU0_SA_DQS_DN<1>")
	)
	(arc
		(start 333.750158 -275.08073)
		(mid 333.702479 -275.26363)
		(end 333.571596 -275.400008)
		(width 0.088646)
		(layer "In4.Cu")
		(net "M_B_CPU0_SA_DQS_DN<1>")
	)
	(arc
		(start 336.852514 -272.96364)
		(mid 336.665316 -273.013783)
		(end 336.478118 -272.96364)
		(width 0.088646)
		(layer "In4.Cu")
		(net "M_B_CPU0_SA_DQS_DN<1>")
	)
	(arc
		(start 334.690212 -273.461734)
		(mid 334.637942 -273.644099)
		(end 334.503014 -273.777456)
		(width 0.088646)
		(layer "In4.Cu")
		(net "M_B_CPU0_SA_DQS_DN<1>")
	)
	(arc
		(start 336.478118 -272.96364)
		(mid 336.201305 -272.88777)
		(end 335.922874 -272.957544)
		(width 0.088646)
		(layer "In4.Cu")
		(net "M_B_CPU0_SA_DQS_DN<1>")
	)
	(arc
		(start 337.79206 -272.96364)
		(mid 337.604862 -273.013783)
		(end 337.417664 -272.96364)
		(width 0.088646)
		(layer "In4.Cu")
		(net "M_B_CPU0_SA_DQS_DN<1>")
	)
	(arc
		(start 339.41385 -272.777204)
		(mid 339.339165 -272.807709)
		(end 339.259164 -272.818098)
		(width 0.088646)
		(layer "In4.Cu")
		(net "M_B_CPU0_SA_DQS_DN<1>")
	)
	(arc
		(start 334.026764 -274.594828)
		(mid 333.824177 -274.801179)
		(end 333.750158 -275.08073)
		(width 0.088646)
		(layer "In4.Cu")
		(net "M_B_CPU0_SA_DQS_DN<1>")
	)
	(arc
		(start 338.732114 -272.96364)
		(mid 338.544916 -273.013783)
		(end 338.357718 -272.96364)
		(width 0.088646)
		(layer "In4.Cu")
		(net "M_B_CPU0_SA_DQS_DN<1>")
	)
	(arc
		(start 333.283814 -275.828252)
		(mid 333.231166 -276.008632)
		(end 333.12227 -276.161754)
		(width 0.088646)
		(layer "In4.Cu")
		(net "M_B_CPU0_SA_DQS_DN<1>")
	)
	(arc
		(start 333.562706 -275.405088)
		(mid 333.373234 -275.58369)
		(end 333.283814 -275.828252)
		(width 0.088646)
		(layer "In4.Cu")
		(net "M_B_CPU0_SA_DQS_DN<1>")
	)
	(arc
		(start 337.417664 -272.96364)
		(mid 337.141105 -272.887897)
		(end 336.862928 -272.957544)
		(width 0.088646)
		(layer "In4.Cu")
		(net "M_B_CPU0_SA_DQS_DN<1>")
	)
	(arc
		(start 334.966818 -272.967196)
		(mid 334.764231 -273.173547)
		(end 334.690212 -273.453098)
		(width 0.088646)
		(layer "In4.Cu")
		(net "M_B_CPU0_SA_DQS_DN<1>")
	)
	(arc
		(start 335.91246 -272.96364)
		(mid 335.725262 -273.013783)
		(end 335.538064 -272.96364)
		(width 0.088646)
		(layer "In4.Cu")
		(net "M_B_CPU0_SA_DQS_DN<1>")
	)
	(arc
		(start 335.538064 -272.96364)
		(mid 335.261505 -272.887897)
		(end 334.983328 -272.957544)
		(width 0.088646)
		(layer "In4.Cu")
		(net "M_B_CPU0_SA_DQS_DN<1>")
	)
	(arc
		(start 338.357718 -272.96364)
		(mid 338.080905 -272.88777)
		(end 337.802474 -272.957544)
		(width 0.088646)
		(layer "In4.Cu")
		(net "M_B_CPU0_SA_DQS_DN<1>")
	)
	(arc
		(start 334.496918 -273.781012)
		(mid 334.294331 -273.987363)
		(end 334.220312 -274.266914)
		(width 0.088646)
		(layer "In4.Cu")
		(net "M_B_CPU0_SA_DQS_DN<1>")
	)
	(segment
		(start 289.027362 -312.48096)
		(end 288.755328 -312.752994)
		(width 0.20066)
		(layer "F.Cu")
		(net "M_B_CPU0_SA_DQS_DN<0>")
	)
	(segment
		(start 287.065466 -312.327798)
		(end 286.804354 -312.066686)
		(width 0.20066)
		(layer "F.Cu")
		(net "M_B_CPU0_SA_DQS_DN<0>")
	)
	(segment
		(start 294.904414 -312.066686)
		(end 293.799514 -312.066686)
		(width 0.20066)
		(layer "F.Cu")
		(net "M_B_CPU0_SA_DQS_DN<0>")
	)
	(segment
		(start 293.799514 -312.066686)
		(end 293.252906 -312.066686)
		(width 0.20066)
		(layer "F.Cu")
		(net "M_B_CPU0_SA_DQS_DN<0>")
	)
	(segment
		(start 288.755328 -312.752994)
		(end 288.215324 -312.752994)
		(width 0.20066)
		(layer "F.Cu")
		(net "M_B_CPU0_SA_DQS_DN<0>")
	)
	(segment
		(start 286.804354 -312.066686)
		(end 286.255714 -312.066686)
		(width 0.20066)
		(layer "F.Cu")
		(net "M_B_CPU0_SA_DQS_DN<0>")
	)
	(segment
		(start 289.23234 -312.48096)
		(end 289.231578 -312.48096)
		(width 0.101854)
		(layer "F.Cu")
		(net "M_B_CPU0_SA_DQS_DN<0>")
	)
	(segment
		(start 292.58514 -312.327798)
		(end 292.159944 -312.752994)
		(width 0.20066)
		(layer "F.Cu")
		(net "M_B_CPU0_SA_DQS_DN<0>")
	)
	(segment
		(start 288.215324 -312.752994)
		(end 287.579308 -312.327798)
		(width 0.20066)
		(layer "F.Cu")
		(net "M_B_CPU0_SA_DQS_DN<0>")
	)
	(segment
		(start 293.252906 -312.066686)
		(end 292.991794 -312.327798)
		(width 0.20066)
		(layer "F.Cu")
		(net "M_B_CPU0_SA_DQS_DN<0>")
	)
	(segment
		(start 287.579308 -312.327798)
		(end 287.065466 -312.327798)
		(width 0.20066)
		(layer "F.Cu")
		(net "M_B_CPU0_SA_DQS_DN<0>")
	)
	(segment
		(start 336.195162 -274.54479)
		(end 336.195162 -275.08073)
		(width 0.20066)
		(layer "F.Cu")
		(net "M_B_CPU0_SA_DQS_DN<0>")
	)
	(segment
		(start 289.243008 -312.491628)
		(end 289.23234 -312.48096)
		(width 0.101854)
		(layer "F.Cu")
		(net "M_B_CPU0_SA_DQS_DN<0>")
	)
	(segment
		(start 292.991794 -312.327798)
		(end 292.58514 -312.327798)
		(width 0.20066)
		(layer "F.Cu")
		(net "M_B_CPU0_SA_DQS_DN<0>")
	)
	(segment
		(start 289.231578 -312.48096)
		(end 289.027362 -312.48096)
		(width 0.20066)
		(layer "F.Cu")
		(net "M_B_CPU0_SA_DQS_DN<0>")
	)
	(segment
		(start 291.556694 -312.491628)
		(end 289.243008 -312.491628)
		(width 0.1016)
		(layer "F.Cu")
		(net "M_B_CPU0_SA_DQS_DN<0>")
	)
	(segment
		(start 291.973254 -312.752994)
		(end 291.711888 -312.491628)
		(width 0.20066)
		(layer "F.Cu")
		(net "M_B_CPU0_SA_DQS_DN<0>")
	)
	(segment
		(start 292.159944 -312.752994)
		(end 291.973254 -312.752994)
		(width 0.20066)
		(layer "F.Cu")
		(net "M_B_CPU0_SA_DQS_DN<0>")
	)
	(segment
		(start 291.711888 -312.491628)
		(end 291.556694 -312.491628)
		(width 0.20066)
		(layer "F.Cu")
		(net "M_B_CPU0_SA_DQS_DN<0>")
	)
	(segment
		(start 303.357026 -312.80481)
		(end 302.579532 -312.80481)
		(width 0.18288)
		(layer "In2.Cu")
		(net "M_B_CPU0_SA_DQS_DN<0>")
	)
	(segment
		(start 309.544466 -313.383676)
		(end 309.516272 -313.41187)
		(width 0.16002)
		(layer "In2.Cu")
		(net "M_B_CPU0_SA_DQS_DN<0>")
	)
	(segment
		(start 306.07 -314.264548)
		(end 304.816764 -314.264548)
		(width 0.18288)
		(layer "In2.Cu")
		(net "M_B_CPU0_SA_DQS_DN<0>")
	)
	(segment
		(start 334.975962 -279.47239)
		(end 334.97393 -279.47366)
		(width 0.088646)
		(layer "In2.Cu")
		(net "M_B_CPU0_SA_DQS_DN<0>")
	)
	(segment
		(start 309.516272 -313.41187)
		(end 309.398924 -313.529218)
		(width 0.18288)
		(layer "In2.Cu")
		(net "M_B_CPU0_SA_DQS_DN<0>")
	)
	(segment
		(start 322.44665 -302.872648)
		(end 322.22694 -303.403508)
		(width 0.18288)
		(layer "In2.Cu")
		(net "M_B_CPU0_SA_DQS_DN<0>")
	)
	(segment
		(start 321.40652 -305.384454)
		(end 321.196716 -305.891184)
		(width 0.18288)
		(layer "In2.Cu")
		(net "M_B_CPU0_SA_DQS_DN<0>")
	)
	(segment
		(start 311.843166 -312.48985)
		(end 311.489598 -312.48985)
		(width 0.18288)
		(layer "In2.Cu")
		(net "M_B_CPU0_SA_DQS_DN<0>")
	)
	(segment
		(start 335.444084 -276.38502)
		(end 335.45018 -276.388576)
		(width 0.088646)
		(layer "In2.Cu")
		(net "M_B_CPU0_SA_DQS_DN<0>")
	)
	(segment
		(start 316.436502 -310.475376)
		(end 316.436502 -310.651398)
		(width 0.18288)
		(layer "In2.Cu")
		(net "M_B_CPU0_SA_DQS_DN<0>")
	)
	(segment
		(start 313.860434 -312.334148)
		(end 313.66079 -312.533792)
		(width 0.16002)
		(layer "In2.Cu")
		(net "M_B_CPU0_SA_DQS_DN<0>")
	)
	(segment
		(start 304.68189 -314.129674)
		(end 304.665634 -314.129674)
		(width 0.16002)
		(layer "In2.Cu")
		(net "M_B_CPU0_SA_DQS_DN<0>")
	)
	(segment
		(start 317.776606 -309.135272)
		(end 317.388494 -309.523384)
		(width 0.18288)
		(layer "In2.Cu")
		(net "M_B_CPU0_SA_DQS_DN<0>")
	)
	(segment
		(start 333.899764 -279.577546)
		(end 333.534004 -279.577546)
		(width 0.088646)
		(layer "In2.Cu")
		(net "M_B_CPU0_SA_DQS_DN<0>")
	)
	(segment
		(start 311.217818 -312.76163)
		(end 310.166512 -312.76163)
		(width 0.18288)
		(layer "In2.Cu")
		(net "M_B_CPU0_SA_DQS_DN<0>")
	)
	(segment
		(start 313.66079 -312.533792)
		(end 313.644534 -312.533792)
		(width 0.16002)
		(layer "In2.Cu")
		(net "M_B_CPU0_SA_DQS_DN<0>")
	)
	(segment
		(start 335.441798 -278.661114)
		(end 335.430876 -278.667464)
		(width 0.088646)
		(layer "In2.Cu")
		(net "M_B_CPU0_SA_DQS_DN<0>")
	)
	(segment
		(start 296.787062 -312.08345)
		(end 296.075608 -312.08345)
		(width 0.18288)
		(layer "In2.Cu")
		(net "M_B_CPU0_SA_DQS_DN<0>")
	)
	(segment
		(start 306.420774 -313.913774)
		(end 306.420774 -313.93003)
		(width 0.16002)
		(layer "In2.Cu")
		(net "M_B_CPU0_SA_DQS_DN<0>")
	)
	(segment
		(start 336.099404 -277.511002)
		(end 336.099404 -277.52294)
		(width 0.088646)
		(layer "In2.Cu")
		(net "M_B_CPU0_SA_DQS_DN<0>")
	)
	(segment
		(start 335.159858 -275.8948)
		(end 335.160112 -275.904706)
		(width 0.088646)
		(layer "In2.Cu")
		(net "M_B_CPU0_SA_DQS_DN<0>")
	)
	(segment
		(start 322.064126 -303.470818)
		(end 321.854322 -303.978056)
		(width 0.18288)
		(layer "In2.Cu")
		(net "M_B_CPU0_SA_DQS_DN<0>")
	)
	(segment
		(start 306.420774 -313.93003)
		(end 306.22113 -314.129674)
		(width 0.16002)
		(layer "In2.Cu")
		(net "M_B_CPU0_SA_DQS_DN<0>")
	)
	(segment
		(start 306.204874 -314.129674)
		(end 306.17668 -314.157868)
		(width 0.16002)
		(layer "In2.Cu")
		(net "M_B_CPU0_SA_DQS_DN<0>")
	)
	(segment
		(start 327.817988 -288.388806)
		(end 324.73646 -295.82745)
		(width 0.18288)
		(layer "In2.Cu")
		(net "M_B_CPU0_SA_DQS_DN<0>")
	)
	(segment
		(start 334.973168 -279.474168)
		(end 334.972406 -279.474676)
		(width 0.088646)
		(layer "In2.Cu")
		(net "M_B_CPU0_SA_DQS_DN<0>")
	)
	(segment
		(start 323.848222 -297.645836)
		(end 323.915532 -297.808396)
		(width 0.18288)
		(layer "In2.Cu")
		(net "M_B_CPU0_SA_DQS_DN<0>")
	)
	(segment
		(start 299.19803 -312.494168)
		(end 298.790868 -312.494168)
		(width 0.18288)
		(layer "In2.Cu")
		(net "M_B_CPU0_SA_DQS_DN<0>")
	)
	(segment
		(start 334.980788 -279.46985)
		(end 334.978248 -279.47112)
		(width 0.088646)
		(layer "In2.Cu")
		(net "M_B_CPU0_SA_DQS_DN<0>")
	)
	(segment
		(start 319.856612 -307.231288)
		(end 319.68059 -307.231288)
		(width 0.18288)
		(layer "In2.Cu")
		(net "M_B_CPU0_SA_DQS_DN<0>")
	)
	(segment
		(start 296.075608 -312.08345)
		(end 295.411398 -312.358532)
		(width 0.18288)
		(layer "In2.Cu")
		(net "M_B_CPU0_SA_DQS_DN<0>")
	)
	(segment
		(start 307.500528 -313.257438)
		(end 307.228748 -313.529218)
		(width 0.18288)
		(layer "In2.Cu")
		(net "M_B_CPU0_SA_DQS_DN<0>")
	)
	(segment
		(start 313.416696 -312.76163)
		(end 312.114946 -312.76163)
		(width 0.18288)
		(layer "In2.Cu")
		(net "M_B_CPU0_SA_DQS_DN<0>")
	)
	(segment
		(start 295.411398 -312.358532)
		(end 295.19626 -312.358532)
		(width 0.18288)
		(layer "In2.Cu")
		(net "M_B_CPU0_SA_DQS_DN<0>")
	)
	(segment
		(start 309.760366 -313.167776)
		(end 309.760366 -313.184032)
		(width 0.16002)
		(layer "In2.Cu")
		(net "M_B_CPU0_SA_DQS_DN<0>")
	)
	(segment
		(start 335.630012 -276.708616)
		(end 335.630012 -276.730714)
		(width 0.088646)
		(layer "In2.Cu")
		(net "M_B_CPU0_SA_DQS_DN<0>")
	)
	(segment
		(start 321.711828 -304.647346)
		(end 321.549014 -304.714656)
		(width 0.18288)
		(layer "In2.Cu")
		(net "M_B_CPU0_SA_DQS_DN<0>")
	)
	(segment
		(start 317.000636 -310.087264)
		(end 316.824614 -310.087264)
		(width 0.18288)
		(layer "In2.Cu")
		(net "M_B_CPU0_SA_DQS_DN<0>")
	)
	(segment
		(start 320.24447 -306.667408)
		(end 320.24447 -306.84343)
		(width 0.18288)
		(layer "In2.Cu")
		(net "M_B_CPU0_SA_DQS_DN<0>")
	)
	(segment
		(start 323.915532 -297.808396)
		(end 323.705728 -298.315126)
		(width 0.18288)
		(layer "In2.Cu")
		(net "M_B_CPU0_SA_DQS_DN<0>")
	)
	(segment
		(start 304.816764 -314.264548)
		(end 304.710084 -314.157868)
		(width 0.18288)
		(layer "In2.Cu")
		(net "M_B_CPU0_SA_DQS_DN<0>")
	)
	(segment
		(start 302.320706 -313.079892)
		(end 302.121062 -313.279536)
		(width 0.16002)
		(layer "In2.Cu")
		(net "M_B_CPU0_SA_DQS_DN<0>")
	)
	(segment
		(start 324.363588 -296.401998)
		(end 324.430898 -296.564558)
		(width 0.18288)
		(layer "In2.Cu")
		(net "M_B_CPU0_SA_DQS_DN<0>")
	)
	(segment
		(start 333.534004 -279.577546)
		(end 333.242412 -279.869138)
		(width 0.088646)
		(layer "In2.Cu")
		(net "M_B_CPU0_SA_DQS_DN<0>")
	)
	(segment
		(start 300.365922 -313.063636)
		(end 300.337728 -313.035442)
		(width 0.16002)
		(layer "In2.Cu")
		(net "M_B_CPU0_SA_DQS_DN<0>")
	)
	(segment
		(start 313.860434 -312.317892)
		(end 313.860434 -312.334148)
		(width 0.16002)
		(layer "In2.Cu")
		(net "M_B_CPU0_SA_DQS_DN<0>")
	)
	(segment
		(start 306.22113 -314.129674)
		(end 306.204874 -314.129674)
		(width 0.16002)
		(layer "In2.Cu")
		(net "M_B_CPU0_SA_DQS_DN<0>")
	)
	(segment
		(start 300.337728 -313.035442)
		(end 300.020482 -312.718196)
		(width 0.18288)
		(layer "In2.Cu")
		(net "M_B_CPU0_SA_DQS_DN<0>")
	)
	(segment
		(start 330.361798 -285.844488)
		(end 327.817734 -288.388806)
		(width 0.18288)
		(layer "In2.Cu")
		(net "M_B_CPU0_SA_DQS_DN<0>")
	)
	(segment
		(start 335.88071 -275.259546)
		(end 335.84388 -275.259546)
		(width 0.088646)
		(layer "In2.Cu")
		(net "M_B_CPU0_SA_DQS_DN<0>")
	)
	(segment
		(start 331.154786 -281.872436)
		(end 331.154786 -283.929074)
		(width 0.18288)
		(layer "In2.Cu")
		(net "M_B_CPU0_SA_DQS_DN<0>")
	)
	(segment
		(start 313.61634 -312.561986)
		(end 313.416696 -312.76163)
		(width 0.18288)
		(layer "In2.Cu")
		(net "M_B_CPU0_SA_DQS_DN<0>")
	)
	(segment
		(start 335.453228 -278.65451)
		(end 335.441798 -278.661114)
		(width 0.088646)
		(layer "In2.Cu")
		(net "M_B_CPU0_SA_DQS_DN<0>")
	)
	(segment
		(start 297.026076 -312.322464)
		(end 296.787062 -312.08345)
		(width 0.18288)
		(layer "In2.Cu")
		(net "M_B_CPU0_SA_DQS_DN<0>")
	)
	(segment
		(start 297.05427 -312.366914)
		(end 297.05427 -312.350658)
		(width 0.16002)
		(layer "In2.Cu")
		(net "M_B_CPU0_SA_DQS_DN<0>")
	)
	(segment
		(start 316.824614 -310.087264)
		(end 316.436502 -310.475376)
		(width 0.18288)
		(layer "In2.Cu")
		(net "M_B_CPU0_SA_DQS_DN<0>")
	)
	(segment
		(start 311.489598 -312.48985)
		(end 311.217818 -312.76163)
		(width 0.18288)
		(layer "In2.Cu")
		(net "M_B_CPU0_SA_DQS_DN<0>")
	)
	(segment
		(start 304.46599 -313.93003)
		(end 304.46599 -313.913774)
		(width 0.16002)
		(layer "In2.Cu")
		(net "M_B_CPU0_SA_DQS_DN<0>")
	)
	(segment
		(start 298.494958 -312.790078)
		(end 297.49369 -312.790078)
		(width 0.18288)
		(layer "In2.Cu")
		(net "M_B_CPU0_SA_DQS_DN<0>")
	)
	(segment
		(start 306.17668 -314.157868)
		(end 306.07 -314.264548)
		(width 0.18288)
		(layer "In2.Cu")
		(net "M_B_CPU0_SA_DQS_DN<0>")
	)
	(segment
		(start 327.817734 -288.388806)
		(end 327.817988 -288.388806)
		(width 0.18288)
		(layer "In2.Cu")
		(net "M_B_CPU0_SA_DQS_DN<0>")
	)
	(segment
		(start 319.292478 -307.795422)
		(end 318.90462 -308.18328)
		(width 0.18288)
		(layer "In2.Cu")
		(net "M_B_CPU0_SA_DQS_DN<0>")
	)
	(segment
		(start 317.388494 -309.523384)
		(end 317.388494 -309.699406)
		(width 0.18288)
		(layer "In2.Cu")
		(net "M_B_CPU0_SA_DQS_DN<0>")
	)
	(segment
		(start 321.921632 -304.140616)
		(end 321.711828 -304.647346)
		(width 0.18288)
		(layer "In2.Cu")
		(net "M_B_CPU0_SA_DQS_DN<0>")
	)
	(segment
		(start 295.19626 -312.358532)
		(end 294.904414 -312.066686)
		(width 0.18288)
		(layer "In2.Cu")
		(net "M_B_CPU0_SA_DQS_DN<0>")
	)
	(segment
		(start 302.579532 -312.80481)
		(end 302.3489 -313.035442)
		(width 0.18288)
		(layer "In2.Cu")
		(net "M_B_CPU0_SA_DQS_DN<0>")
	)
	(segment
		(start 336.195162 -275.08073)
		(end 335.88071 -275.259546)
		(width 0.088646)
		(layer "In2.Cu")
		(net "M_B_CPU0_SA_DQS_DN<0>")
	)
	(segment
		(start 324.05828 -297.138598)
		(end 323.848222 -297.645836)
		(width 0.18288)
		(layer "In2.Cu")
		(net "M_B_CPU0_SA_DQS_DN<0>")
	)
	(segment
		(start 315.63564 -311.45226)
		(end 314.07862 -312.099706)
		(width 0.18288)
		(layer "In2.Cu")
		(net "M_B_CPU0_SA_DQS_DN<0>")
	)
	(segment
		(start 335.159858 -275.876258)
		(end 335.159858 -275.8948)
		(width 0.088646)
		(layer "In2.Cu")
		(net "M_B_CPU0_SA_DQS_DN<0>")
	)
	(segment
		(start 320.632582 -306.279296)
		(end 320.24447 -306.667408)
		(width 0.18288)
		(layer "In2.Cu")
		(net "M_B_CPU0_SA_DQS_DN<0>")
	)
	(segment
		(start 300.365922 -313.079892)
		(end 300.365922 -313.063636)
		(width 0.16002)
		(layer "In2.Cu")
		(net "M_B_CPU0_SA_DQS_DN<0>")
	)
	(segment
		(start 314.07862 -312.099706)
		(end 313.888628 -312.289698)
		(width 0.18288)
		(layer "In2.Cu")
		(net "M_B_CPU0_SA_DQS_DN<0>")
	)
	(segment
		(start 310.166512 -312.76163)
		(end 309.78856 -313.139582)
		(width 0.18288)
		(layer "In2.Cu")
		(net "M_B_CPU0_SA_DQS_DN<0>")
	)
	(segment
		(start 318.728598 -308.18328)
		(end 318.340486 -308.571392)
		(width 0.18288)
		(layer "In2.Cu")
		(net "M_B_CPU0_SA_DQS_DN<0>")
	)
	(segment
		(start 318.90462 -308.18328)
		(end 318.728598 -308.18328)
		(width 0.18288)
		(layer "In2.Cu")
		(net "M_B_CPU0_SA_DQS_DN<0>")
	)
	(segment
		(start 324.430898 -296.564558)
		(end 324.221094 -297.071288)
		(width 0.18288)
		(layer "In2.Cu")
		(net "M_B_CPU0_SA_DQS_DN<0>")
	)
	(segment
		(start 334.983836 -279.468072)
		(end 334.980788 -279.46985)
		(width 0.088646)
		(layer "In2.Cu")
		(net "M_B_CPU0_SA_DQS_DN<0>")
	)
	(segment
		(start 335.84388 -275.259546)
		(end 335.565242 -275.334222)
		(width 0.088646)
		(layer "In2.Cu")
		(net "M_B_CPU0_SA_DQS_DN<0>")
	)
	(segment
		(start 313.888628 -312.289698)
		(end 313.860434 -312.317892)
		(width 0.16002)
		(layer "In2.Cu")
		(net "M_B_CPU0_SA_DQS_DN<0>")
	)
	(segment
		(start 309.760366 -313.184032)
		(end 309.560722 -313.383676)
		(width 0.16002)
		(layer "In2.Cu")
		(net "M_B_CPU0_SA_DQS_DN<0>")
	)
	(segment
		(start 300.716696 -313.41441)
		(end 300.610016 -313.30773)
		(width 0.18288)
		(layer "In2.Cu")
		(net "M_B_CPU0_SA_DQS_DN<0>")
	)
	(segment
		(start 321.33921 -305.221894)
		(end 321.40652 -305.384454)
		(width 0.18288)
		(layer "In2.Cu")
		(net "M_B_CPU0_SA_DQS_DN<0>")
	)
	(segment
		(start 321.549014 -304.714656)
		(end 321.33921 -305.221894)
		(width 0.18288)
		(layer "In2.Cu")
		(net "M_B_CPU0_SA_DQS_DN<0>")
	)
	(segment
		(start 297.49369 -312.790078)
		(end 297.298364 -312.594752)
		(width 0.18288)
		(layer "In2.Cu")
		(net "M_B_CPU0_SA_DQS_DN<0>")
	)
	(segment
		(start 312.114946 -312.76163)
		(end 311.843166 -312.48985)
		(width 0.18288)
		(layer "In2.Cu")
		(net "M_B_CPU0_SA_DQS_DN<0>")
	)
	(segment
		(start 334.609948 -279.481534)
		(end 334.573372 -279.460452)
		(width 0.088646)
		(layer "In2.Cu")
		(net "M_B_CPU0_SA_DQS_DN<0>")
	)
	(segment
		(start 300.610016 -313.30773)
		(end 300.581822 -313.279536)
		(width 0.16002)
		(layer "In2.Cu")
		(net "M_B_CPU0_SA_DQS_DN<0>")
	)
	(segment
		(start 302.104806 -313.279536)
		(end 302.076612 -313.30773)
		(width 0.16002)
		(layer "In2.Cu")
		(net "M_B_CPU0_SA_DQS_DN<0>")
	)
	(segment
		(start 309.560722 -313.383676)
		(end 309.544466 -313.383676)
		(width 0.16002)
		(layer "In2.Cu")
		(net "M_B_CPU0_SA_DQS_DN<0>")
	)
	(segment
		(start 335.911952 -277.847298)
		(end 335.89595 -277.856696)
		(width 0.088646)
		(layer "In2.Cu")
		(net "M_B_CPU0_SA_DQS_DN<0>")
	)
	(segment
		(start 334.978248 -279.47112)
		(end 334.975962 -279.47239)
		(width 0.088646)
		(layer "In2.Cu")
		(net "M_B_CPU0_SA_DQS_DN<0>")
	)
	(segment
		(start 297.253914 -312.566558)
		(end 297.05427 -312.366914)
		(width 0.16002)
		(layer "In2.Cu")
		(net "M_B_CPU0_SA_DQS_DN<0>")
	)
	(segment
		(start 297.298364 -312.594752)
		(end 297.27017 -312.566558)
		(width 0.16002)
		(layer "In2.Cu")
		(net "M_B_CPU0_SA_DQS_DN<0>")
	)
	(segment
		(start 320.24447 -306.84343)
		(end 319.856612 -307.231288)
		(width 0.18288)
		(layer "In2.Cu")
		(net "M_B_CPU0_SA_DQS_DN<0>")
	)
	(segment
		(start 319.292478 -307.6194)
		(end 319.292478 -307.795422)
		(width 0.18288)
		(layer "In2.Cu")
		(net "M_B_CPU0_SA_DQS_DN<0>")
	)
	(segment
		(start 324.73646 -295.82745)
		(end 324.573646 -295.89476)
		(width 0.18288)
		(layer "In2.Cu")
		(net "M_B_CPU0_SA_DQS_DN<0>")
	)
	(segment
		(start 309.78856 -313.139582)
		(end 309.760366 -313.167776)
		(width 0.16002)
		(layer "In2.Cu")
		(net "M_B_CPU0_SA_DQS_DN<0>")
	)
	(segment
		(start 313.644534 -312.533792)
		(end 313.61634 -312.561986)
		(width 0.16002)
		(layer "In2.Cu")
		(net "M_B_CPU0_SA_DQS_DN<0>")
	)
	(segment
		(start 306.448968 -313.88558)
		(end 306.420774 -313.913774)
		(width 0.16002)
		(layer "In2.Cu")
		(net "M_B_CPU0_SA_DQS_DN<0>")
	)
	(segment
		(start 309.398924 -313.529218)
		(end 308.125876 -313.529218)
		(width 0.18288)
		(layer "In2.Cu")
		(net "M_B_CPU0_SA_DQS_DN<0>")
	)
	(segment
		(start 331.154786 -283.929074)
		(end 331.02042 -284.253432)
		(width 0.18288)
		(layer "In2.Cu")
		(net "M_B_CPU0_SA_DQS_DN<0>")
	)
	(segment
		(start 304.46599 -313.913774)
		(end 304.437796 -313.88558)
		(width 0.16002)
		(layer "In2.Cu")
		(net "M_B_CPU0_SA_DQS_DN<0>")
	)
	(segment
		(start 321.196716 -305.891184)
		(end 320.808604 -306.279296)
		(width 0.18288)
		(layer "In2.Cu")
		(net "M_B_CPU0_SA_DQS_DN<0>")
	)
	(segment
		(start 323.705728 -298.315126)
		(end 323.542914 -298.382436)
		(width 0.18288)
		(layer "In2.Cu")
		(net "M_B_CPU0_SA_DQS_DN<0>")
	)
	(segment
		(start 323.027802 -299.951394)
		(end 322.446904 -302.872648)
		(width 0.18288)
		(layer "In2.Cu")
		(net "M_B_CPU0_SA_DQS_DN<0>")
	)
	(segment
		(start 304.665634 -314.129674)
		(end 304.46599 -313.93003)
		(width 0.16002)
		(layer "In2.Cu")
		(net "M_B_CPU0_SA_DQS_DN<0>")
	)
	(segment
		(start 334.030828 -279.46096)
		(end 334.03032 -279.461214)
		(width 0.088646)
		(layer "In2.Cu")
		(net "M_B_CPU0_SA_DQS_DN<0>")
	)
	(segment
		(start 334.972152 -279.474676)
		(end 334.973168 -279.474168)
		(width 0.088646)
		(layer "In2.Cu")
		(net "M_B_CPU0_SA_DQS_DN<0>")
	)
	(segment
		(start 300.020482 -312.718196)
		(end 299.422058 -312.718196)
		(width 0.18288)
		(layer "In2.Cu")
		(net "M_B_CPU0_SA_DQS_DN<0>")
	)
	(segment
		(start 302.320706 -313.063636)
		(end 302.320706 -313.079892)
		(width 0.16002)
		(layer "In2.Cu")
		(net "M_B_CPU0_SA_DQS_DN<0>")
	)
	(segment
		(start 297.05427 -312.350658)
		(end 297.026076 -312.322464)
		(width 0.16002)
		(layer "In2.Cu")
		(net "M_B_CPU0_SA_DQS_DN<0>")
	)
	(segment
		(start 317.952628 -309.135272)
		(end 317.776606 -309.135272)
		(width 0.18288)
		(layer "In2.Cu")
		(net "M_B_CPU0_SA_DQS_DN<0>")
	)
	(segment
		(start 335.565242 -275.334222)
		(end 335.442306 -275.405088)
		(width 0.088646)
		(layer "In2.Cu")
		(net "M_B_CPU0_SA_DQS_DN<0>")
	)
	(segment
		(start 331.02042 -284.253432)
		(end 330.361798 -285.844488)
		(width 0.18288)
		(layer "In2.Cu")
		(net "M_B_CPU0_SA_DQS_DN<0>")
	)
	(segment
		(start 318.340486 -308.747414)
		(end 317.952628 -309.135272)
		(width 0.18288)
		(layer "In2.Cu")
		(net "M_B_CPU0_SA_DQS_DN<0>")
	)
	(segment
		(start 302.3489 -313.035442)
		(end 302.320706 -313.063636)
		(width 0.16002)
		(layer "In2.Cu")
		(net "M_B_CPU0_SA_DQS_DN<0>")
	)
	(segment
		(start 333.158084 -279.869138)
		(end 331.154786 -281.872436)
		(width 0.18288)
		(layer "In2.Cu")
		(net "M_B_CPU0_SA_DQS_DN<0>")
	)
	(segment
		(start 298.790868 -312.494168)
		(end 298.494958 -312.790078)
		(width 0.18288)
		(layer "In2.Cu")
		(net "M_B_CPU0_SA_DQS_DN<0>")
	)
	(segment
		(start 302.076612 -313.30773)
		(end 301.969932 -313.41441)
		(width 0.18288)
		(layer "In2.Cu")
		(net "M_B_CPU0_SA_DQS_DN<0>")
	)
	(segment
		(start 324.221094 -297.071288)
		(end 324.05828 -297.138598)
		(width 0.18288)
		(layer "In2.Cu")
		(net "M_B_CPU0_SA_DQS_DN<0>")
	)
	(segment
		(start 335.920842 -277.842218)
		(end 335.911952 -277.847298)
		(width 0.088646)
		(layer "In2.Cu")
		(net "M_B_CPU0_SA_DQS_DN<0>")
	)
	(segment
		(start 333.242412 -279.869138)
		(end 333.158084 -279.869138)
		(width 0.088646)
		(layer "In2.Cu")
		(net "M_B_CPU0_SA_DQS_DN<0>")
	)
	(segment
		(start 319.68059 -307.231288)
		(end 319.292478 -307.6194)
		(width 0.18288)
		(layer "In2.Cu")
		(net "M_B_CPU0_SA_DQS_DN<0>")
	)
	(segment
		(start 324.573646 -295.89476)
		(end 324.363588 -296.401998)
		(width 0.18288)
		(layer "In2.Cu")
		(net "M_B_CPU0_SA_DQS_DN<0>")
	)
	(segment
		(start 304.710084 -314.157868)
		(end 304.68189 -314.129674)
		(width 0.16002)
		(layer "In2.Cu")
		(net "M_B_CPU0_SA_DQS_DN<0>")
	)
	(segment
		(start 297.27017 -312.566558)
		(end 297.253914 -312.566558)
		(width 0.16002)
		(layer "In2.Cu")
		(net "M_B_CPU0_SA_DQS_DN<0>")
	)
	(segment
		(start 321.854322 -303.978056)
		(end 321.921632 -304.140616)
		(width 0.18288)
		(layer "In2.Cu")
		(net "M_B_CPU0_SA_DQS_DN<0>")
	)
	(segment
		(start 307.854096 -313.257438)
		(end 307.500528 -313.257438)
		(width 0.18288)
		(layer "In2.Cu")
		(net "M_B_CPU0_SA_DQS_DN<0>")
	)
	(segment
		(start 316.436502 -310.651398)
		(end 315.63564 -311.45226)
		(width 0.18288)
		(layer "In2.Cu")
		(net "M_B_CPU0_SA_DQS_DN<0>")
	)
	(segment
		(start 306.80533 -313.529218)
		(end 306.448968 -313.88558)
		(width 0.18288)
		(layer "In2.Cu")
		(net "M_B_CPU0_SA_DQS_DN<0>")
	)
	(segment
		(start 322.446904 -302.872648)
		(end 322.44665 -302.872648)
		(width 0.18288)
		(layer "In2.Cu")
		(net "M_B_CPU0_SA_DQS_DN<0>")
	)
	(segment
		(start 333.992982 -279.48763)
		(end 333.98968 -279.49017)
		(width 0.088646)
		(layer "In2.Cu")
		(net "M_B_CPU0_SA_DQS_DN<0>")
	)
	(segment
		(start 322.22694 -303.403508)
		(end 322.064126 -303.470818)
		(width 0.18288)
		(layer "In2.Cu")
		(net "M_B_CPU0_SA_DQS_DN<0>")
	)
	(segment
		(start 308.125876 -313.529218)
		(end 307.854096 -313.257438)
		(width 0.18288)
		(layer "In2.Cu")
		(net "M_B_CPU0_SA_DQS_DN<0>")
	)
	(segment
		(start 307.228748 -313.529218)
		(end 306.80533 -313.529218)
		(width 0.18288)
		(layer "In2.Cu")
		(net "M_B_CPU0_SA_DQS_DN<0>")
	)
	(segment
		(start 318.340486 -308.571392)
		(end 318.340486 -308.747414)
		(width 0.18288)
		(layer "In2.Cu")
		(net "M_B_CPU0_SA_DQS_DN<0>")
	)
	(segment
		(start 301.969932 -313.41441)
		(end 300.716696 -313.41441)
		(width 0.18288)
		(layer "In2.Cu")
		(net "M_B_CPU0_SA_DQS_DN<0>")
	)
	(segment
		(start 302.121062 -313.279536)
		(end 302.104806 -313.279536)
		(width 0.16002)
		(layer "In2.Cu")
		(net "M_B_CPU0_SA_DQS_DN<0>")
	)
	(segment
		(start 334.97393 -279.47366)
		(end 334.972152 -279.474676)
		(width 0.088646)
		(layer "In2.Cu")
		(net "M_B_CPU0_SA_DQS_DN<0>")
	)
	(segment
		(start 317.388494 -309.699406)
		(end 317.000636 -310.087264)
		(width 0.18288)
		(layer "In2.Cu")
		(net "M_B_CPU0_SA_DQS_DN<0>")
	)
	(segment
		(start 335.44256 -276.384258)
		(end 335.444084 -276.38502)
		(width 0.088646)
		(layer "In2.Cu")
		(net "M_B_CPU0_SA_DQS_DN<0>")
	)
	(segment
		(start 323.542914 -298.382436)
		(end 323.332856 -298.88942)
		(width 0.18288)
		(layer "In2.Cu")
		(net "M_B_CPU0_SA_DQS_DN<0>")
	)
	(segment
		(start 304.437796 -313.88558)
		(end 303.357026 -312.80481)
		(width 0.18288)
		(layer "In2.Cu")
		(net "M_B_CPU0_SA_DQS_DN<0>")
	)
	(segment
		(start 300.581822 -313.279536)
		(end 300.565566 -313.279536)
		(width 0.16002)
		(layer "In2.Cu")
		(net "M_B_CPU0_SA_DQS_DN<0>")
	)
	(segment
		(start 333.98968 -279.49017)
		(end 333.899764 -279.577546)
		(width 0.088646)
		(layer "In2.Cu")
		(net "M_B_CPU0_SA_DQS_DN<0>")
	)
	(segment
		(start 323.332856 -298.88942)
		(end 323.400166 -299.052234)
		(width 0.18288)
		(layer "In2.Cu")
		(net "M_B_CPU0_SA_DQS_DN<0>")
	)
	(segment
		(start 320.808604 -306.279296)
		(end 320.632582 -306.279296)
		(width 0.18288)
		(layer "In2.Cu")
		(net "M_B_CPU0_SA_DQS_DN<0>")
	)
	(segment
		(start 323.400166 -299.052234)
		(end 323.027802 -299.951394)
		(width 0.18288)
		(layer "In2.Cu")
		(net "M_B_CPU0_SA_DQS_DN<0>")
	)
	(segment
		(start 299.422058 -312.718196)
		(end 299.19803 -312.494168)
		(width 0.18288)
		(layer "In2.Cu")
		(net "M_B_CPU0_SA_DQS_DN<0>")
	)
	(segment
		(start 300.565566 -313.279536)
		(end 300.365922 -313.079892)
		(width 0.16002)
		(layer "In2.Cu")
		(net "M_B_CPU0_SA_DQS_DN<0>")
	)
	(arc
		(start 334.03032 -279.461214)
		(mid 334.011032 -279.473548)
		(end 333.992982 -279.48763)
		(width 0.088646)
		(layer "In2.Cu")
		(net "M_B_CPU0_SA_DQS_DN<0>")
	)
	(arc
		(start 335.430876 -278.667464)
		(mid 335.232016 -278.873514)
		(end 335.159604 -279.150572)
		(width 0.088646)
		(layer "In2.Cu")
		(net "M_B_CPU0_SA_DQS_DN<0>")
	)
	(arc
		(start 335.628996 -278.33701)
		(mid 335.582122 -278.518464)
		(end 335.453228 -278.65451)
		(width 0.088646)
		(layer "In2.Cu")
		(net "M_B_CPU0_SA_DQS_DN<0>")
	)
	(arc
		(start 335.442306 -275.405088)
		(mid 335.24002 -275.604069)
		(end 335.159858 -275.876258)
		(width 0.088646)
		(layer "In2.Cu")
		(net "M_B_CPU0_SA_DQS_DN<0>")
	)
	(arc
		(start 335.912206 -277.198328)
		(mid 336.046364 -277.330383)
		(end 336.099404 -277.511002)
		(width 0.088646)
		(layer "In2.Cu")
		(net "M_B_CPU0_SA_DQS_DN<0>")
	)
	(arc
		(start 335.160112 -275.904706)
		(mid 335.238223 -276.181655)
		(end 335.44256 -276.384258)
		(width 0.088646)
		(layer "In2.Cu")
		(net "M_B_CPU0_SA_DQS_DN<0>")
	)
	(arc
		(start 335.45018 -276.388576)
		(mid 335.581991 -276.525059)
		(end 335.630012 -276.708616)
		(width 0.088646)
		(layer "In2.Cu")
		(net "M_B_CPU0_SA_DQS_DN<0>")
	)
	(arc
		(start 335.89595 -277.856696)
		(mid 335.700162 -278.062233)
		(end 335.628996 -278.33701)
		(width 0.088646)
		(layer "In2.Cu")
		(net "M_B_CPU0_SA_DQS_DN<0>")
	)
	(arc
		(start 334.972406 -279.474676)
		(mid 334.792059 -279.524913)
		(end 334.609948 -279.481534)
		(width 0.088646)
		(layer "In2.Cu")
		(net "M_B_CPU0_SA_DQS_DN<0>")
	)
	(arc
		(start 335.630012 -276.730714)
		(mid 335.710923 -277.000842)
		(end 335.912206 -277.198328)
		(width 0.088646)
		(layer "In2.Cu")
		(net "M_B_CPU0_SA_DQS_DN<0>")
	)
	(arc
		(start 336.099404 -277.52294)
		(mid 336.051725 -277.70584)
		(end 335.920842 -277.842218)
		(width 0.088646)
		(layer "In2.Cu")
		(net "M_B_CPU0_SA_DQS_DN<0>")
	)
	(arc
		(start 334.573372 -279.460452)
		(mid 334.302041 -279.388025)
		(end 334.030828 -279.46096)
		(width 0.088646)
		(layer "In2.Cu")
		(net "M_B_CPU0_SA_DQS_DN<0>")
	)
	(arc
		(start 335.159604 -279.150572)
		(mid 335.11273 -279.332026)
		(end 334.983836 -279.468072)
		(width 0.088646)
		(layer "In2.Cu")
		(net "M_B_CPU0_SA_DQS_DN<0>")
	)
	(segment
		(start 288.46018 -304.995326)
		(end 288.46018 -305.323494)
		(width 0.20066)
		(layer "F.Cu")
		(net "M_B_CPU0_SA_DQ<9>")
	)
	(segment
		(start 289.240468 -304.841656)
		(end 289.231578 -304.832766)
		(width 0.1016)
		(layer "F.Cu")
		(net "M_B_CPU0_SA_DQ<9>")
	)
	(segment
		(start 294.904414 -305.266598)
		(end 293.799514 -305.266598)
		(width 0.20066)
		(layer "F.Cu")
		(net "M_B_CPU0_SA_DQ<9>")
	)
	(segment
		(start 291.556694 -304.841656)
		(end 291.225986 -304.841656)
		(width 0.101854)
		(layer "F.Cu")
		(net "M_B_CPU0_SA_DQ<9>")
	)
	(segment
		(start 292.160198 -305.266598)
		(end 291.735256 -304.841656)
		(width 0.20066)
		(layer "F.Cu")
		(net "M_B_CPU0_SA_DQ<9>")
	)
	(segment
		(start 291.735256 -304.841656)
		(end 291.556694 -304.841656)
		(width 0.20066)
		(layer "F.Cu")
		(net "M_B_CPU0_SA_DQ<9>")
	)
	(segment
		(start 293.799514 -305.266598)
		(end 292.160198 -305.266598)
		(width 0.20066)
		(layer "F.Cu")
		(net "M_B_CPU0_SA_DQ<9>")
	)
	(segment
		(start 288.46018 -305.323494)
		(end 288.305748 -305.477926)
		(width 0.20066)
		(layer "F.Cu")
		(net "M_B_CPU0_SA_DQ<9>")
	)
	(segment
		(start 288.305748 -305.477926)
		(end 287.801304 -305.477926)
		(width 0.20066)
		(layer "F.Cu")
		(net "M_B_CPU0_SA_DQ<9>")
	)
	(segment
		(start 288.62274 -304.832766)
		(end 288.46018 -304.995326)
		(width 0.20066)
		(layer "F.Cu")
		(net "M_B_CPU0_SA_DQ<9>")
	)
	(segment
		(start 289.231578 -304.832766)
		(end 288.62274 -304.832766)
		(width 0.20066)
		(layer "F.Cu")
		(net "M_B_CPU0_SA_DQ<9>")
	)
	(segment
		(start 287.589976 -305.266598)
		(end 286.255714 -305.266598)
		(width 0.20066)
		(layer "F.Cu")
		(net "M_B_CPU0_SA_DQ<9>")
	)
	(segment
		(start 287.801304 -305.477926)
		(end 287.589976 -305.266598)
		(width 0.20066)
		(layer "F.Cu")
		(net "M_B_CPU0_SA_DQ<9>")
	)
	(segment
		(start 291.225986 -304.841656)
		(end 289.240468 -304.841656)
		(width 0.1016)
		(layer "F.Cu")
		(net "M_B_CPU0_SA_DQ<9>")
	)
	(arc
		(start 339.954362 -272.917158)
		(mid 339.954425 -273.185128)
		(end 339.954616 -273.453098)
		(width 0.20066)
		(layer "F.Cu")
		(net "M_B_CPU0_SA_DQ<9>")
	)
	(segment
		(start 298.215812 -305.691794)
		(end 298.055792 -305.851814)
		(width 0.18288)
		(layer "In4.Cu")
		(net "M_B_CPU0_SA_DQ<9>")
	)
	(segment
		(start 295.32961 -305.691794)
		(end 294.904414 -305.266598)
		(width 0.18288)
		(layer "In4.Cu")
		(net "M_B_CPU0_SA_DQ<9>")
	)
	(segment
		(start 339.297518 -273.942556)
		(end 339.287104 -273.948652)
		(width 0.088646)
		(layer "In4.Cu")
		(net "M_B_CPU0_SA_DQ<9>")
	)
	(segment
		(start 300.377352 -305.691794)
		(end 300.247558 -305.562)
		(width 0.18288)
		(layer "In4.Cu")
		(net "M_B_CPU0_SA_DQ<9>")
	)
	(segment
		(start 297.872912 -306.32908)
		(end 297.524932 -306.32908)
		(width 0.18288)
		(layer "In4.Cu")
		(net "M_B_CPU0_SA_DQ<9>")
	)
	(segment
		(start 297.364912 -305.9049)
		(end 297.204892 -305.74488)
		(width 0.18288)
		(layer "In4.Cu")
		(net "M_B_CPU0_SA_DQ<9>")
	)
	(segment
		(start 322.377054 -293.710868)
		(end 314.64631 -301.441612)
		(width 0.18288)
		(layer "In4.Cu")
		(net "M_B_CPU0_SA_DQ<9>")
	)
	(segment
		(start 296.674032 -305.92776)
		(end 296.674032 -306.141882)
		(width 0.18288)
		(layer "In4.Cu")
		(net "M_B_CPU0_SA_DQ<9>")
	)
	(segment
		(start 307.534056 -303.991772)
		(end 306.87518 -304.650648)
		(width 0.18288)
		(layer "In4.Cu")
		(net "M_B_CPU0_SA_DQ<9>")
	)
	(segment
		(start 303.056036 -305.691794)
		(end 300.377352 -305.691794)
		(width 0.18288)
		(layer "In4.Cu")
		(net "M_B_CPU0_SA_DQ<9>")
	)
	(segment
		(start 295.823132 -305.691794)
		(end 295.32961 -305.691794)
		(width 0.18288)
		(layer "In4.Cu")
		(net "M_B_CPU0_SA_DQ<9>")
	)
	(segment
		(start 304.097182 -304.650648)
		(end 303.056036 -305.691794)
		(width 0.18288)
		(layer "In4.Cu")
		(net "M_B_CPU0_SA_DQ<9>")
	)
	(segment
		(start 297.364912 -306.16906)
		(end 297.364912 -305.9049)
		(width 0.18288)
		(layer "In4.Cu")
		(net "M_B_CPU0_SA_DQ<9>")
	)
	(segment
		(start 339.71484 -273.552412)
		(end 339.415628 -273.851624)
		(width 0.088646)
		(layer "In4.Cu")
		(net "M_B_CPU0_SA_DQ<9>")
	)
	(segment
		(start 298.055792 -305.851814)
		(end 298.055792 -306.1462)
		(width 0.18288)
		(layer "In4.Cu")
		(net "M_B_CPU0_SA_DQ<9>")
	)
	(segment
		(start 333.65821 -277.198328)
		(end 333.643478 -277.206964)
		(width 0.088646)
		(layer "In4.Cu")
		(net "M_B_CPU0_SA_DQ<9>")
	)
	(segment
		(start 299.177202 -305.691794)
		(end 298.215812 -305.691794)
		(width 0.18288)
		(layer "In4.Cu")
		(net "M_B_CPU0_SA_DQ<9>")
	)
	(segment
		(start 298.055792 -306.1462)
		(end 297.872912 -306.32908)
		(width 0.18288)
		(layer "In4.Cu")
		(net "M_B_CPU0_SA_DQ<9>")
	)
	(segment
		(start 296.166032 -306.324762)
		(end 295.983152 -306.141882)
		(width 0.18288)
		(layer "In4.Cu")
		(net "M_B_CPU0_SA_DQ<9>")
	)
	(segment
		(start 335.06791 -274.756372)
		(end 335.05902 -274.761452)
		(width 0.088646)
		(layer "In4.Cu")
		(net "M_B_CPU0_SA_DQ<9>")
	)
	(segment
		(start 310.568848 -302.97628)
		(end 310.568848 -303.68748)
		(width 0.18288)
		(layer "In4.Cu")
		(net "M_B_CPU0_SA_DQ<9>")
	)
	(segment
		(start 300.247558 -305.562)
		(end 299.306996 -305.562)
		(width 0.18288)
		(layer "In4.Cu")
		(net "M_B_CPU0_SA_DQ<9>")
	)
	(segment
		(start 332.3971 -278.883364)
		(end 332.198218 -279.082246)
		(width 0.088646)
		(layer "In4.Cu")
		(net "M_B_CPU0_SA_DQ<9>")
	)
	(segment
		(start 295.983152 -306.141882)
		(end 295.983152 -305.851814)
		(width 0.18288)
		(layer "In4.Cu")
		(net "M_B_CPU0_SA_DQ<9>")
	)
	(segment
		(start 333.940912 -276.708616)
		(end 333.940912 -276.72284)
		(width 0.088646)
		(layer "In4.Cu")
		(net "M_B_CPU0_SA_DQ<9>")
	)
	(segment
		(start 310.264556 -303.991772)
		(end 307.534056 -303.991772)
		(width 0.18288)
		(layer "In4.Cu")
		(net "M_B_CPU0_SA_DQ<9>")
	)
	(segment
		(start 312.344816 -302.03648)
		(end 311.508648 -302.03648)
		(width 0.18288)
		(layer "In4.Cu")
		(net "M_B_CPU0_SA_DQ<9>")
	)
	(segment
		(start 297.524932 -306.32908)
		(end 297.364912 -306.16906)
		(width 0.18288)
		(layer "In4.Cu")
		(net "M_B_CPU0_SA_DQ<9>")
	)
	(segment
		(start 325.776336 -285.504128)
		(end 322.377054 -293.710868)
		(width 0.18288)
		(layer "In4.Cu")
		(net "M_B_CPU0_SA_DQ<9>")
	)
	(segment
		(start 297.204892 -305.74488)
		(end 296.856912 -305.74488)
		(width 0.18288)
		(layer "In4.Cu")
		(net "M_B_CPU0_SA_DQ<9>")
	)
	(segment
		(start 310.568848 -303.68748)
		(end 310.264556 -303.991772)
		(width 0.18288)
		(layer "In4.Cu")
		(net "M_B_CPU0_SA_DQ<9>")
	)
	(segment
		(start 334.880458 -275.08073)
		(end 334.880458 -275.099272)
		(width 0.088646)
		(layer "In4.Cu")
		(net "M_B_CPU0_SA_DQ<9>")
	)
	(segment
		(start 306.87518 -304.650648)
		(end 304.097182 -304.650648)
		(width 0.18288)
		(layer "In4.Cu")
		(net "M_B_CPU0_SA_DQ<9>")
	)
	(segment
		(start 296.856912 -305.74488)
		(end 296.674032 -305.92776)
		(width 0.18288)
		(layer "In4.Cu")
		(net "M_B_CPU0_SA_DQ<9>")
	)
	(segment
		(start 295.983152 -305.851814)
		(end 295.823132 -305.691794)
		(width 0.18288)
		(layer "In4.Cu")
		(net "M_B_CPU0_SA_DQ<9>")
	)
	(segment
		(start 335.538064 -273.942556)
		(end 335.529174 -273.947636)
		(width 0.088646)
		(layer "In4.Cu")
		(net "M_B_CPU0_SA_DQ<9>")
	)
	(segment
		(start 314.64631 -301.441612)
		(end 312.939684 -301.441612)
		(width 0.18288)
		(layer "In4.Cu")
		(net "M_B_CPU0_SA_DQ<9>")
	)
	(segment
		(start 334.128364 -276.384258)
		(end 334.119474 -276.389338)
		(width 0.088646)
		(layer "In4.Cu")
		(net "M_B_CPU0_SA_DQ<9>")
	)
	(segment
		(start 334.59801 -275.570442)
		(end 334.58912 -275.575522)
		(width 0.088646)
		(layer "In4.Cu")
		(net "M_B_CPU0_SA_DQ<9>")
	)
	(segment
		(start 296.674032 -306.141882)
		(end 296.491152 -306.324762)
		(width 0.18288)
		(layer "In4.Cu")
		(net "M_B_CPU0_SA_DQ<9>")
	)
	(segment
		(start 312.939684 -301.441612)
		(end 312.344816 -302.03648)
		(width 0.18288)
		(layer "In4.Cu")
		(net "M_B_CPU0_SA_DQ<9>")
	)
	(segment
		(start 332.198218 -279.082246)
		(end 325.776336 -285.504128)
		(width 0.18288)
		(layer "In4.Cu")
		(net "M_B_CPU0_SA_DQ<9>")
	)
	(segment
		(start 334.410558 -275.8948)
		(end 334.410558 -275.910294)
		(width 0.088646)
		(layer "In4.Cu")
		(net "M_B_CPU0_SA_DQ<9>")
	)
	(segment
		(start 332.3971 -278.437594)
		(end 332.3971 -278.883364)
		(width 0.088646)
		(layer "In4.Cu")
		(net "M_B_CPU0_SA_DQ<9>")
	)
	(segment
		(start 299.306996 -305.562)
		(end 299.177202 -305.691794)
		(width 0.18288)
		(layer "In4.Cu")
		(net "M_B_CPU0_SA_DQ<9>")
	)
	(segment
		(start 296.491152 -306.324762)
		(end 296.166032 -306.324762)
		(width 0.18288)
		(layer "In4.Cu")
		(net "M_B_CPU0_SA_DQ<9>")
	)
	(segment
		(start 335.074006 -274.752816)
		(end 335.06791 -274.756372)
		(width 0.088646)
		(layer "In4.Cu")
		(net "M_B_CPU0_SA_DQ<9>")
	)
	(segment
		(start 333.609188 -277.225506)
		(end 332.3971 -278.437594)
		(width 0.088646)
		(layer "In4.Cu")
		(net "M_B_CPU0_SA_DQ<9>")
	)
	(segment
		(start 311.508648 -302.03648)
		(end 310.568848 -302.97628)
		(width 0.18288)
		(layer "In4.Cu")
		(net "M_B_CPU0_SA_DQ<9>")
	)
	(arc
		(start 338.357464 -273.942556)
		(mid 338.074762 -274.018332)
		(end 337.79206 -273.942556)
		(width 0.088646)
		(layer "In4.Cu")
		(net "M_B_CPU0_SA_DQ<9>")
	)
	(arc
		(start 334.119474 -276.389338)
		(mid 333.98856 -276.525698)
		(end 333.940912 -276.708616)
		(width 0.088646)
		(layer "In4.Cu")
		(net "M_B_CPU0_SA_DQ<9>")
	)
	(arc
		(start 335.05902 -274.761452)
		(mid 334.928106 -274.897812)
		(end 334.880458 -275.08073)
		(width 0.088646)
		(layer "In4.Cu")
		(net "M_B_CPU0_SA_DQ<9>")
	)
	(arc
		(start 335.529174 -273.947636)
		(mid 335.39826 -274.083996)
		(end 335.350612 -274.266914)
		(width 0.088646)
		(layer "In4.Cu")
		(net "M_B_CPU0_SA_DQ<9>")
	)
	(arc
		(start 339.287104 -273.948652)
		(mid 339.008672 -274.018498)
		(end 338.73186 -273.942556)
		(width 0.088646)
		(layer "In4.Cu")
		(net "M_B_CPU0_SA_DQ<9>")
	)
	(arc
		(start 333.643478 -277.206964)
		(mid 333.635889 -277.211086)
		(end 333.628238 -277.215092)
		(width 0.088646)
		(layer "In4.Cu")
		(net "M_B_CPU0_SA_DQ<9>")
	)
	(arc
		(start 333.628238 -277.215092)
		(mid 333.618614 -277.220118)
		(end 333.609188 -277.225506)
		(width 0.088646)
		(layer "In4.Cu")
		(net "M_B_CPU0_SA_DQ<9>")
	)
	(arc
		(start 337.79206 -273.942556)
		(mid 337.604862 -273.892413)
		(end 337.417664 -273.942556)
		(width 0.088646)
		(layer "In4.Cu")
		(net "M_B_CPU0_SA_DQ<9>")
	)
	(arc
		(start 333.940912 -276.72284)
		(mid 333.861693 -276.997525)
		(end 333.65821 -277.198328)
		(width 0.088646)
		(layer "In4.Cu")
		(net "M_B_CPU0_SA_DQ<9>")
	)
	(arc
		(start 335.91246 -273.942556)
		(mid 335.725262 -273.892413)
		(end 335.538064 -273.942556)
		(width 0.088646)
		(layer "In4.Cu")
		(net "M_B_CPU0_SA_DQ<9>")
	)
	(arc
		(start 335.350612 -274.266914)
		(mid 335.276621 -274.54648)
		(end 335.074006 -274.752816)
		(width 0.088646)
		(layer "In4.Cu")
		(net "M_B_CPU0_SA_DQ<9>")
	)
	(arc
		(start 334.880458 -275.099272)
		(mid 334.800296 -275.371461)
		(end 334.59801 -275.570442)
		(width 0.088646)
		(layer "In4.Cu")
		(net "M_B_CPU0_SA_DQ<9>")
	)
	(arc
		(start 334.58912 -275.575522)
		(mid 334.458206 -275.711882)
		(end 334.410558 -275.8948)
		(width 0.088646)
		(layer "In4.Cu")
		(net "M_B_CPU0_SA_DQ<9>")
	)
	(arc
		(start 334.410558 -275.910294)
		(mid 334.331188 -276.184028)
		(end 334.128364 -276.384258)
		(width 0.088646)
		(layer "In4.Cu")
		(net "M_B_CPU0_SA_DQ<9>")
	)
	(arc
		(start 339.954616 -273.453098)
		(mid 339.824852 -273.47891)
		(end 339.71484 -273.552412)
		(width 0.088646)
		(layer "In4.Cu")
		(net "M_B_CPU0_SA_DQ<9>")
	)
	(arc
		(start 338.73186 -273.942556)
		(mid 338.544662 -273.892413)
		(end 338.357464 -273.942556)
		(width 0.088646)
		(layer "In4.Cu")
		(net "M_B_CPU0_SA_DQ<9>")
	)
	(arc
		(start 336.477864 -273.942556)
		(mid 336.195162 -274.018332)
		(end 335.91246 -273.942556)
		(width 0.088646)
		(layer "In4.Cu")
		(net "M_B_CPU0_SA_DQ<9>")
	)
	(arc
		(start 336.85226 -273.942556)
		(mid 336.665062 -273.892413)
		(end 336.477864 -273.942556)
		(width 0.088646)
		(layer "In4.Cu")
		(net "M_B_CPU0_SA_DQ<9>")
	)
	(arc
		(start 337.417664 -273.942556)
		(mid 337.134962 -274.018332)
		(end 336.85226 -273.942556)
		(width 0.088646)
		(layer "In4.Cu")
		(net "M_B_CPU0_SA_DQ<9>")
	)
	(arc
		(start 339.415628 -273.851624)
		(mid 339.35958 -273.900994)
		(end 339.297518 -273.942556)
		(width 0.088646)
		(layer "In4.Cu")
		(net "M_B_CPU0_SA_DQ<9>")
	)
	(segment
		(start 289.231578 -306.53355)
		(end 288.66973 -306.53355)
		(width 0.20066)
		(layer "F.Cu")
		(net "M_B_CPU0_SA_DQ<8>")
	)
	(segment
		(start 288.46018 -307.03266)
		(end 288.28746 -307.20538)
		(width 0.20066)
		(layer "F.Cu")
		(net "M_B_CPU0_SA_DQ<8>")
	)
	(segment
		(start 340.424516 -273.730974)
		(end 340.424516 -274.26666)
		(width 0.20066)
		(layer "F.Cu")
		(net "M_B_CPU0_SA_DQ<8>")
	)
	(segment
		(start 294.904414 -306.96662)
		(end 293.799514 -306.96662)
		(width 0.20066)
		(layer "F.Cu")
		(net "M_B_CPU0_SA_DQ<8>")
	)
	(segment
		(start 287.828736 -307.20538)
		(end 287.589976 -306.96662)
		(width 0.20066)
		(layer "F.Cu")
		(net "M_B_CPU0_SA_DQ<8>")
	)
	(segment
		(start 288.46018 -306.7431)
		(end 288.46018 -307.03266)
		(width 0.20066)
		(layer "F.Cu")
		(net "M_B_CPU0_SA_DQ<8>")
	)
	(segment
		(start 340.424516 -274.26666)
		(end 340.424262 -274.266914)
		(width 0.20066)
		(layer "F.Cu")
		(net "M_B_CPU0_SA_DQ<8>")
	)
	(segment
		(start 288.66973 -306.53355)
		(end 288.46018 -306.7431)
		(width 0.20066)
		(layer "F.Cu")
		(net "M_B_CPU0_SA_DQ<8>")
	)
	(segment
		(start 289.48761 -306.541678)
		(end 289.239706 -306.541678)
		(width 0.101854)
		(layer "F.Cu")
		(net "M_B_CPU0_SA_DQ<8>")
	)
	(segment
		(start 291.556694 -306.541678)
		(end 289.48761 -306.541678)
		(width 0.1016)
		(layer "F.Cu")
		(net "M_B_CPU0_SA_DQ<8>")
	)
	(segment
		(start 292.005512 -306.541678)
		(end 291.556694 -306.541678)
		(width 0.20066)
		(layer "F.Cu")
		(net "M_B_CPU0_SA_DQ<8>")
	)
	(segment
		(start 287.589976 -306.96662)
		(end 286.255714 -306.96662)
		(width 0.20066)
		(layer "F.Cu")
		(net "M_B_CPU0_SA_DQ<8>")
	)
	(segment
		(start 289.239706 -306.541678)
		(end 289.231578 -306.53355)
		(width 0.101854)
		(layer "F.Cu")
		(net "M_B_CPU0_SA_DQ<8>")
	)
	(segment
		(start 288.28746 -307.20538)
		(end 287.828736 -307.20538)
		(width 0.20066)
		(layer "F.Cu")
		(net "M_B_CPU0_SA_DQ<8>")
	)
	(segment
		(start 292.430454 -306.96662)
		(end 292.005512 -306.541678)
		(width 0.20066)
		(layer "F.Cu")
		(net "M_B_CPU0_SA_DQ<8>")
	)
	(segment
		(start 293.799514 -306.96662)
		(end 292.430454 -306.96662)
		(width 0.20066)
		(layer "F.Cu")
		(net "M_B_CPU0_SA_DQ<8>")
	)
	(segment
		(start 333.845662 -278.219916)
		(end 333.845662 -278.859234)
		(width 0.088646)
		(layer "In4.Cu")
		(net "M_B_CPU0_SA_DQ<8>")
	)
	(segment
		(start 338.272374 -274.762468)
		(end 338.26196 -274.756372)
		(width 0.088646)
		(layer "In4.Cu")
		(net "M_B_CPU0_SA_DQ<8>")
	)
	(segment
		(start 339.767164 -274.756372)
		(end 339.75675 -274.762468)
		(width 0.088646)
		(layer "In4.Cu")
		(net "M_B_CPU0_SA_DQ<8>")
	)
	(segment
		(start 326.667622 -286.037274)
		(end 323.135244 -294.565832)
		(width 0.18288)
		(layer "In4.Cu")
		(net "M_B_CPU0_SA_DQ<8>")
	)
	(segment
		(start 336.007964 -274.756372)
		(end 335.999074 -274.761452)
		(width 0.088646)
		(layer "In4.Cu")
		(net "M_B_CPU0_SA_DQ<8>")
	)
	(segment
		(start 339.847936 -274.709636)
		(end 339.77326 -274.752816)
		(width 0.088646)
		(layer "In4.Cu")
		(net "M_B_CPU0_SA_DQ<8>")
	)
	(segment
		(start 335.820512 -275.08073)
		(end 335.820512 -275.08835)
		(width 0.088646)
		(layer "In4.Cu")
		(net "M_B_CPU0_SA_DQ<8>")
	)
	(segment
		(start 315.338968 -303.000664)
		(end 314.34786 -303.991772)
		(width 0.18288)
		(layer "In4.Cu")
		(net "M_B_CPU0_SA_DQ<8>")
	)
	(segment
		(start 299.928788 -307.293264)
		(end 299.177202 -306.541678)
		(width 0.18288)
		(layer "In4.Cu")
		(net "M_B_CPU0_SA_DQ<8>")
	)
	(segment
		(start 295.32961 -307.391816)
		(end 294.904414 -306.96662)
		(width 0.18288)
		(layer "In4.Cu")
		(net "M_B_CPU0_SA_DQ<8>")
	)
	(segment
		(start 333.845662 -278.859234)
		(end 332.910434 -279.794462)
		(width 0.088646)
		(layer "In4.Cu")
		(net "M_B_CPU0_SA_DQ<8>")
	)
	(segment
		(start 307.53685 -305.691794)
		(end 306.842668 -306.385976)
		(width 0.18288)
		(layer "In4.Cu")
		(net "M_B_CPU0_SA_DQ<8>")
	)
	(segment
		(start 296.287698 -307.551836)
		(end 296.127678 -307.391816)
		(width 0.18288)
		(layer "In4.Cu")
		(net "M_B_CPU0_SA_DQ<8>")
	)
	(segment
		(start 334.880712 -276.708616)
		(end 334.880712 -276.72284)
		(width 0.088646)
		(layer "In4.Cu")
		(net "M_B_CPU0_SA_DQ<8>")
	)
	(segment
		(start 296.978578 -307.89626)
		(end 296.818558 -308.05628)
		(width 0.18288)
		(layer "In4.Cu")
		(net "M_B_CPU0_SA_DQ<8>")
	)
	(segment
		(start 298.794424 -306.541678)
		(end 297.944286 -307.391816)
		(width 0.18288)
		(layer "In4.Cu")
		(net "M_B_CPU0_SA_DQ<8>")
	)
	(segment
		(start 310.748934 -305.691794)
		(end 307.53685 -305.691794)
		(width 0.18288)
		(layer "In4.Cu")
		(net "M_B_CPU0_SA_DQ<8>")
	)
	(segment
		(start 296.287698 -307.8734)
		(end 296.287698 -307.551836)
		(width 0.18288)
		(layer "In4.Cu")
		(net "M_B_CPU0_SA_DQ<8>")
	)
	(segment
		(start 333.99857 -278.067008)
		(end 333.845662 -278.219916)
		(width 0.088646)
		(layer "In4.Cu")
		(net "M_B_CPU0_SA_DQ<8>")
	)
	(segment
		(start 296.818558 -308.05628)
		(end 296.470578 -308.05628)
		(width 0.18288)
		(layer "In4.Cu")
		(net "M_B_CPU0_SA_DQ<8>")
	)
	(segment
		(start 297.944286 -307.391816)
		(end 297.138598 -307.391816)
		(width 0.18288)
		(layer "In4.Cu")
		(net "M_B_CPU0_SA_DQ<8>")
	)
	(segment
		(start 335.53781 -275.570442)
		(end 335.52892 -275.575522)
		(width 0.088646)
		(layer "In4.Cu")
		(net "M_B_CPU0_SA_DQ<8>")
	)
	(segment
		(start 334.410558 -277.522686)
		(end 334.410558 -277.53818)
		(width 0.088646)
		(layer "In4.Cu")
		(net "M_B_CPU0_SA_DQ<8>")
	)
	(segment
		(start 334.59801 -277.198328)
		(end 334.58912 -277.203408)
		(width 0.088646)
		(layer "In4.Cu")
		(net "M_B_CPU0_SA_DQ<8>")
	)
	(segment
		(start 296.978578 -307.551836)
		(end 296.978578 -307.89626)
		(width 0.18288)
		(layer "In4.Cu")
		(net "M_B_CPU0_SA_DQ<8>")
	)
	(segment
		(start 335.350358 -275.8948)
		(end 335.350358 -275.910294)
		(width 0.088646)
		(layer "In4.Cu")
		(net "M_B_CPU0_SA_DQ<8>")
	)
	(segment
		(start 339.77326 -274.752816)
		(end 339.767164 -274.756372)
		(width 0.088646)
		(layer "In4.Cu")
		(net "M_B_CPU0_SA_DQ<8>")
	)
	(segment
		(start 314.34786 -303.991772)
		(end 312.448956 -303.991772)
		(width 0.18288)
		(layer "In4.Cu")
		(net "M_B_CPU0_SA_DQ<8>")
	)
	(segment
		(start 299.177202 -306.541678)
		(end 298.794424 -306.541678)
		(width 0.18288)
		(layer "In4.Cu")
		(net "M_B_CPU0_SA_DQ<8>")
	)
	(segment
		(start 296.127678 -307.391816)
		(end 295.32961 -307.391816)
		(width 0.18288)
		(layer "In4.Cu")
		(net "M_B_CPU0_SA_DQ<8>")
	)
	(segment
		(start 303.97958 -306.385976)
		(end 303.072292 -307.293264)
		(width 0.18288)
		(layer "In4.Cu")
		(net "M_B_CPU0_SA_DQ<8>")
	)
	(segment
		(start 297.138598 -307.391816)
		(end 296.978578 -307.551836)
		(width 0.18288)
		(layer "In4.Cu")
		(net "M_B_CPU0_SA_DQ<8>")
	)
	(segment
		(start 296.470578 -308.05628)
		(end 296.287698 -307.8734)
		(width 0.18288)
		(layer "In4.Cu")
		(net "M_B_CPU0_SA_DQ<8>")
	)
	(segment
		(start 335.068164 -276.384258)
		(end 335.059274 -276.389338)
		(width 0.088646)
		(layer "In4.Cu")
		(net "M_B_CPU0_SA_DQ<8>")
	)
	(segment
		(start 315.338968 -302.362108)
		(end 315.338968 -303.000664)
		(width 0.18288)
		(layer "In4.Cu")
		(net "M_B_CPU0_SA_DQ<8>")
	)
	(segment
		(start 332.910434 -279.794462)
		(end 326.667622 -286.037274)
		(width 0.18288)
		(layer "In4.Cu")
		(net "M_B_CPU0_SA_DQ<8>")
	)
	(segment
		(start 323.135244 -294.565832)
		(end 315.338968 -302.362108)
		(width 0.18288)
		(layer "In4.Cu")
		(net "M_B_CPU0_SA_DQ<8>")
	)
	(segment
		(start 312.448956 -303.991772)
		(end 310.748934 -305.691794)
		(width 0.18288)
		(layer "In4.Cu")
		(net "M_B_CPU0_SA_DQ<8>")
	)
	(segment
		(start 306.842668 -306.385976)
		(end 303.97958 -306.385976)
		(width 0.18288)
		(layer "In4.Cu")
		(net "M_B_CPU0_SA_DQ<8>")
	)
	(segment
		(start 303.072292 -307.293264)
		(end 299.928788 -307.293264)
		(width 0.18288)
		(layer "In4.Cu")
		(net "M_B_CPU0_SA_DQ<8>")
	)
	(arc
		(start 339.202014 -274.756372)
		(mid 339.014816 -274.706229)
		(end 338.827618 -274.756372)
		(width 0.088646)
		(layer "In4.Cu")
		(net "M_B_CPU0_SA_DQ<8>")
	)
	(arc
		(start 340.424262 -274.266914)
		(mid 340.150515 -274.507043)
		(end 339.847936 -274.709636)
		(width 0.088646)
		(layer "In4.Cu")
		(net "M_B_CPU0_SA_DQ<8>")
	)
	(arc
		(start 337.32216 -274.756372)
		(mid 337.134962 -274.706229)
		(end 336.947764 -274.756372)
		(width 0.088646)
		(layer "In4.Cu")
		(net "M_B_CPU0_SA_DQ<8>")
	)
	(arc
		(start 337.887564 -274.756372)
		(mid 337.604862 -274.832148)
		(end 337.32216 -274.756372)
		(width 0.088646)
		(layer "In4.Cu")
		(net "M_B_CPU0_SA_DQ<8>")
	)
	(arc
		(start 339.75675 -274.762468)
		(mid 339.478572 -274.832191)
		(end 339.202014 -274.756372)
		(width 0.088646)
		(layer "In4.Cu")
		(net "M_B_CPU0_SA_DQ<8>")
	)
	(arc
		(start 336.38236 -274.756372)
		(mid 336.195162 -274.706229)
		(end 336.007964 -274.756372)
		(width 0.088646)
		(layer "In4.Cu")
		(net "M_B_CPU0_SA_DQ<8>")
	)
	(arc
		(start 334.410558 -277.53818)
		(mid 334.291314 -277.870184)
		(end 333.99857 -278.067008)
		(width 0.088646)
		(layer "In4.Cu")
		(net "M_B_CPU0_SA_DQ<8>")
	)
	(arc
		(start 334.880712 -276.72284)
		(mid 334.801493 -276.997525)
		(end 334.59801 -277.198328)
		(width 0.088646)
		(layer "In4.Cu")
		(net "M_B_CPU0_SA_DQ<8>")
	)
	(arc
		(start 335.820512 -275.08835)
		(mid 335.742883 -275.366763)
		(end 335.53781 -275.570442)
		(width 0.088646)
		(layer "In4.Cu")
		(net "M_B_CPU0_SA_DQ<8>")
	)
	(arc
		(start 334.58912 -277.203408)
		(mid 334.458206 -277.339768)
		(end 334.410558 -277.522686)
		(width 0.088646)
		(layer "In4.Cu")
		(net "M_B_CPU0_SA_DQ<8>")
	)
	(arc
		(start 335.350358 -275.910294)
		(mid 335.270988 -276.184028)
		(end 335.068164 -276.384258)
		(width 0.088646)
		(layer "In4.Cu")
		(net "M_B_CPU0_SA_DQ<8>")
	)
	(arc
		(start 335.52892 -275.575522)
		(mid 335.398006 -275.711882)
		(end 335.350358 -275.8948)
		(width 0.088646)
		(layer "In4.Cu")
		(net "M_B_CPU0_SA_DQ<8>")
	)
	(arc
		(start 336.947764 -274.756372)
		(mid 336.665062 -274.832148)
		(end 336.38236 -274.756372)
		(width 0.088646)
		(layer "In4.Cu")
		(net "M_B_CPU0_SA_DQ<8>")
	)
	(arc
		(start 338.827618 -274.756372)
		(mid 338.550805 -274.832242)
		(end 338.272374 -274.762468)
		(width 0.088646)
		(layer "In4.Cu")
		(net "M_B_CPU0_SA_DQ<8>")
	)
	(arc
		(start 335.059274 -276.389338)
		(mid 334.92836 -276.525698)
		(end 334.880712 -276.708616)
		(width 0.088646)
		(layer "In4.Cu")
		(net "M_B_CPU0_SA_DQ<8>")
	)
	(arc
		(start 335.999074 -274.761452)
		(mid 335.86816 -274.897812)
		(end 335.820512 -275.08073)
		(width 0.088646)
		(layer "In4.Cu")
		(net "M_B_CPU0_SA_DQ<8>")
	)
	(arc
		(start 338.26196 -274.756372)
		(mid 338.074762 -274.706229)
		(end 337.887564 -274.756372)
		(width 0.088646)
		(layer "In4.Cu")
		(net "M_B_CPU0_SA_DQ<8>")
	)
	(segment
		(start 292.927532 -308.2417)
		(end 292.689534 -308.2417)
		(width 0.101854)
		(layer "F.Cu")
		(net "M_B_CPU0_SA_DQ<7>")
	)
	(segment
		(start 338.074762 -272.917158)
		(end 338.074762 -273.453098)
		(width 0.20066)
		(layer "F.Cu")
		(net "M_B_CPU0_SA_DQ<7>")
	)
	(segment
		(start 297.08348 -307.816758)
		(end 296.875962 -308.024276)
		(width 0.20066)
		(layer "F.Cu")
		(net "M_B_CPU0_SA_DQ<7>")
	)
	(segment
		(start 292.67531 -308.255924)
		(end 292.321488 -308.255924)
		(width 0.20066)
		(layer "F.Cu")
		(net "M_B_CPU0_SA_DQ<7>")
	)
	(segment
		(start 296.875962 -308.024276)
		(end 296.42943 -308.024276)
		(width 0.20066)
		(layer "F.Cu")
		(net "M_B_CPU0_SA_DQ<7>")
	)
	(segment
		(start 292.689534 -308.2417)
		(end 292.67531 -308.255924)
		(width 0.101854)
		(layer "F.Cu")
		(net "M_B_CPU0_SA_DQ<7>")
	)
	(segment
		(start 295.544748 -308.2417)
		(end 295.000426 -308.2417)
		(width 0.20066)
		(layer "F.Cu")
		(net "M_B_CPU0_SA_DQ<7>")
	)
	(segment
		(start 292.178994 -308.11343)
		(end 292.178994 -307.942742)
		(width 0.20066)
		(layer "F.Cu")
		(net "M_B_CPU0_SA_DQ<7>")
	)
	(segment
		(start 296.42943 -308.024276)
		(end 296.217594 -307.81244)
		(width 0.20066)
		(layer "F.Cu")
		(net "M_B_CPU0_SA_DQ<7>")
	)
	(segment
		(start 292.178994 -307.942742)
		(end 292.05301 -307.816758)
		(width 0.20066)
		(layer "F.Cu")
		(net "M_B_CPU0_SA_DQ<7>")
	)
	(segment
		(start 296.217594 -307.81244)
		(end 295.82237 -307.81244)
		(width 0.20066)
		(layer "F.Cu")
		(net "M_B_CPU0_SA_DQ<7>")
	)
	(segment
		(start 299.029882 -307.816758)
		(end 297.899582 -307.816758)
		(width 0.20066)
		(layer "F.Cu")
		(net "M_B_CPU0_SA_DQ<7>")
	)
	(segment
		(start 295.82237 -307.81244)
		(end 295.693846 -307.940964)
		(width 0.20066)
		(layer "F.Cu")
		(net "M_B_CPU0_SA_DQ<7>")
	)
	(segment
		(start 297.899582 -307.816758)
		(end 297.08348 -307.816758)
		(width 0.20066)
		(layer "F.Cu")
		(net "M_B_CPU0_SA_DQ<7>")
	)
	(segment
		(start 292.321488 -308.255924)
		(end 292.178994 -308.11343)
		(width 0.20066)
		(layer "F.Cu")
		(net "M_B_CPU0_SA_DQ<7>")
	)
	(segment
		(start 295.000426 -308.2417)
		(end 292.927532 -308.2417)
		(width 0.1016)
		(layer "F.Cu")
		(net "M_B_CPU0_SA_DQ<7>")
	)
	(segment
		(start 292.05301 -307.816758)
		(end 290.355782 -307.816758)
		(width 0.20066)
		(layer "F.Cu")
		(net "M_B_CPU0_SA_DQ<7>")
	)
	(segment
		(start 295.693846 -308.092602)
		(end 295.544748 -308.2417)
		(width 0.20066)
		(layer "F.Cu")
		(net "M_B_CPU0_SA_DQ<7>")
	)
	(segment
		(start 295.693846 -307.940964)
		(end 295.693846 -308.092602)
		(width 0.20066)
		(layer "F.Cu")
		(net "M_B_CPU0_SA_DQ<7>")
	)
	(segment
		(start 303.741328 -306.2986)
		(end 303.741328 -304.67554)
		(width 0.18288)
		(layer "In2.Cu")
		(net "M_B_CPU0_SA_DQ<7>")
	)
	(segment
		(start 305.700176 -306.872894)
		(end 305.158902 -306.872894)
		(width 0.18288)
		(layer "In2.Cu")
		(net "M_B_CPU0_SA_DQ<7>")
	)
	(segment
		(start 312.445908 -306.841398)
		(end 312.445908 -307.263546)
		(width 0.18288)
		(layer "In2.Cu")
		(net "M_B_CPU0_SA_DQ<7>")
	)
	(segment
		(start 300.8376 -306.427124)
		(end 300.67758 -306.587144)
		(width 0.18288)
		(layer "In2.Cu")
		(net "M_B_CPU0_SA_DQ<7>")
	)
	(segment
		(start 313.26455 -306.808124)
		(end 313.10453 -306.648104)
		(width 0.18288)
		(layer "In2.Cu")
		(net "M_B_CPU0_SA_DQ<7>")
	)
	(segment
		(start 332.620366 -276.382734)
		(end 332.62316 -276.384258)
		(width 0.088646)
		(layer "In2.Cu")
		(net "M_B_CPU0_SA_DQ<7>")
	)
	(segment
		(start 320.42481 -298.34713)
		(end 319.849754 -301.238158)
		(width 0.18288)
		(layer "In2.Cu")
		(net "M_B_CPU0_SA_DQ<7>")
	)
	(segment
		(start 333.572104 -273.772376)
		(end 333.563214 -273.777456)
		(width 0.088646)
		(layer "In2.Cu")
		(net "M_B_CPU0_SA_DQ<7>")
	)
	(segment
		(start 309.116476 -307.89245)
		(end 308.74716 -308.261766)
		(width 0.18288)
		(layer "In2.Cu")
		(net "M_B_CPU0_SA_DQ<7>")
	)
	(segment
		(start 329.102466 -281.374088)
		(end 328.63155 -282.510992)
		(width 0.18288)
		(layer "In2.Cu")
		(net "M_B_CPU0_SA_DQ<7>")
	)
	(segment
		(start 308.220872 -307.608986)
		(end 307.138832 -306.526946)
		(width 0.18288)
		(layer "In2.Cu")
		(net "M_B_CPU0_SA_DQ<7>")
	)
	(segment
		(start 332.631796 -275.400008)
		(end 332.622906 -275.405088)
		(width 0.088646)
		(layer "In2.Cu")
		(net "M_B_CPU0_SA_DQ<7>")
	)
	(segment
		(start 335.927446 -272.955004)
		(end 335.912714 -272.96364)
		(width 0.088646)
		(layer "In2.Cu")
		(net "M_B_CPU0_SA_DQ<7>")
	)
	(segment
		(start 315.148976 -307.659532)
		(end 314.17387 -307.659532)
		(width 0.18288)
		(layer "In2.Cu")
		(net "M_B_CPU0_SA_DQ<7>")
	)
	(segment
		(start 309.38978 -307.89245)
		(end 309.116476 -307.89245)
		(width 0.18288)
		(layer "In2.Cu")
		(net "M_B_CPU0_SA_DQ<7>")
	)
	(segment
		(start 333.10195 -274.586192)
		(end 333.09306 -274.591272)
		(width 0.088646)
		(layer "In2.Cu")
		(net "M_B_CPU0_SA_DQ<7>")
	)
	(segment
		(start 313.909456 -307.395118)
		(end 313.429142 -307.395118)
		(width 0.18288)
		(layer "In2.Cu")
		(net "M_B_CPU0_SA_DQ<7>")
	)
	(segment
		(start 303.207928 -304.49774)
		(end 303.02962 -304.676048)
		(width 0.18288)
		(layer "In2.Cu")
		(net "M_B_CPU0_SA_DQ<7>")
	)
	(segment
		(start 305.158902 -306.872894)
		(end 304.812954 -306.526946)
		(width 0.18288)
		(layer "In2.Cu")
		(net "M_B_CPU0_SA_DQ<7>")
	)
	(segment
		(start 301.639732 -306.417218)
		(end 301.639732 -305.89728)
		(width 0.18288)
		(layer "In2.Cu")
		(net "M_B_CPU0_SA_DQ<7>")
	)
	(segment
		(start 328.63155 -282.510992)
		(end 327.954386 -284.145736)
		(width 0.18288)
		(layer "In2.Cu")
		(net "M_B_CPU0_SA_DQ<7>")
	)
	(segment
		(start 332.336648 -277.349712)
		(end 331.952854 -277.733506)
		(width 0.088646)
		(layer "In2.Cu")
		(net "M_B_CPU0_SA_DQ<7>")
	)
	(segment
		(start 307.138832 -306.526946)
		(end 306.046124 -306.526946)
		(width 0.18288)
		(layer "In2.Cu")
		(net "M_B_CPU0_SA_DQ<7>")
	)
	(segment
		(start 301.03064 -305.70424)
		(end 300.8376 -305.89728)
		(width 0.18288)
		(layer "In2.Cu")
		(net "M_B_CPU0_SA_DQ<7>")
	)
	(segment
		(start 332.62316 -276.384258)
		(end 332.63205 -276.389338)
		(width 0.088646)
		(layer "In2.Cu")
		(net "M_B_CPU0_SA_DQ<7>")
	)
	(segment
		(start 308.380892 -308.261766)
		(end 308.220872 -308.101746)
		(width 0.18288)
		(layer "In2.Cu")
		(net "M_B_CPU0_SA_DQ<7>")
	)
	(segment
		(start 311.979564 -307.423566)
		(end 311.146444 -307.687472)
		(width 0.18288)
		(layer "In2.Cu")
		(net "M_B_CPU0_SA_DQ<7>")
	)
	(segment
		(start 310.551322 -308.282594)
		(end 309.779924 -308.282594)
		(width 0.18288)
		(layer "In2.Cu")
		(net "M_B_CPU0_SA_DQ<7>")
	)
	(segment
		(start 338.074762 -273.453098)
		(end 337.761834 -273.453098)
		(width 0.088646)
		(layer "In2.Cu")
		(net "M_B_CPU0_SA_DQ<7>")
	)
	(segment
		(start 309.779924 -308.282594)
		(end 309.38978 -307.89245)
		(width 0.18288)
		(layer "In2.Cu")
		(net "M_B_CPU0_SA_DQ<7>")
	)
	(segment
		(start 333.280258 -274.266914)
		(end 333.280512 -274.266914)
		(width 0.088646)
		(layer "In2.Cu")
		(net "M_B_CPU0_SA_DQ<7>")
	)
	(segment
		(start 308.74716 -308.261766)
		(end 308.380892 -308.261766)
		(width 0.18288)
		(layer "In2.Cu")
		(net "M_B_CPU0_SA_DQ<7>")
	)
	(segment
		(start 303.563528 -304.49774)
		(end 303.207928 -304.49774)
		(width 0.18288)
		(layer "In2.Cu")
		(net "M_B_CPU0_SA_DQ<7>")
	)
	(segment
		(start 303.969674 -306.526946)
		(end 303.741328 -306.2986)
		(width 0.18288)
		(layer "In2.Cu")
		(net "M_B_CPU0_SA_DQ<7>")
	)
	(segment
		(start 337.761834 -273.453098)
		(end 337.696556 -273.38782)
		(width 0.088646)
		(layer "In2.Cu")
		(net "M_B_CPU0_SA_DQ<7>")
	)
	(segment
		(start 329.102466 -280.583894)
		(end 329.102466 -281.374088)
		(width 0.18288)
		(layer "In2.Cu")
		(net "M_B_CPU0_SA_DQ<7>")
	)
	(segment
		(start 332.336648 -277.292054)
		(end 332.336648 -277.349712)
		(width 0.088646)
		(layer "In2.Cu")
		(net "M_B_CPU0_SA_DQ<7>")
	)
	(segment
		(start 313.429142 -307.395118)
		(end 313.26455 -307.230526)
		(width 0.18288)
		(layer "In2.Cu")
		(net "M_B_CPU0_SA_DQ<7>")
	)
	(segment
		(start 301.446692 -305.70424)
		(end 301.03064 -305.70424)
		(width 0.18288)
		(layer "In2.Cu")
		(net "M_B_CPU0_SA_DQ<7>")
	)
	(segment
		(start 313.26455 -307.230526)
		(end 313.26455 -306.808124)
		(width 0.18288)
		(layer "In2.Cu")
		(net "M_B_CPU0_SA_DQ<7>")
	)
	(segment
		(start 332.63205 -277.027894)
		(end 332.62316 -277.032974)
		(width 0.088646)
		(layer "In2.Cu")
		(net "M_B_CPU0_SA_DQ<7>")
	)
	(segment
		(start 312.285888 -307.423566)
		(end 311.979564 -307.423566)
		(width 0.18288)
		(layer "In2.Cu")
		(net "M_B_CPU0_SA_DQ<7>")
	)
	(segment
		(start 300.8376 -305.89728)
		(end 300.8376 -306.427124)
		(width 0.18288)
		(layer "In2.Cu")
		(net "M_B_CPU0_SA_DQ<7>")
	)
	(segment
		(start 336.862928 -272.957544)
		(end 336.852514 -272.96364)
		(width 0.088646)
		(layer "In2.Cu")
		(net "M_B_CPU0_SA_DQ<7>")
	)
	(segment
		(start 331.952854 -277.733506)
		(end 329.102466 -280.583894)
		(width 0.18288)
		(layer "In2.Cu")
		(net "M_B_CPU0_SA_DQ<7>")
	)
	(segment
		(start 311.146444 -307.687472)
		(end 310.551322 -308.282594)
		(width 0.18288)
		(layer "In2.Cu")
		(net "M_B_CPU0_SA_DQ<7>")
	)
	(segment
		(start 312.445908 -307.263546)
		(end 312.285888 -307.423566)
		(width 0.18288)
		(layer "In2.Cu")
		(net "M_B_CPU0_SA_DQ<7>")
	)
	(segment
		(start 333.750666 -273.443192)
		(end 333.750666 -273.453098)
		(width 0.088646)
		(layer "In2.Cu")
		(net "M_B_CPU0_SA_DQ<7>")
	)
	(segment
		(start 332.340458 -275.876258)
		(end 332.340458 -275.8948)
		(width 0.088646)
		(layer "In2.Cu")
		(net "M_B_CPU0_SA_DQ<7>")
	)
	(segment
		(start 304.812954 -306.526946)
		(end 303.969674 -306.526946)
		(width 0.18288)
		(layer "In2.Cu")
		(net "M_B_CPU0_SA_DQ<7>")
	)
	(segment
		(start 301.639732 -305.89728)
		(end 301.446692 -305.70424)
		(width 0.18288)
		(layer "In2.Cu")
		(net "M_B_CPU0_SA_DQ<7>")
	)
	(segment
		(start 313.10453 -306.648104)
		(end 312.639202 -306.648104)
		(width 0.18288)
		(layer "In2.Cu")
		(net "M_B_CPU0_SA_DQ<7>")
	)
	(segment
		(start 332.617064 -276.380702)
		(end 332.620366 -276.382734)
		(width 0.088646)
		(layer "In2.Cu")
		(net "M_B_CPU0_SA_DQ<7>")
	)
	(segment
		(start 303.741328 -304.67554)
		(end 303.563528 -304.49774)
		(width 0.18288)
		(layer "In2.Cu")
		(net "M_B_CPU0_SA_DQ<7>")
	)
	(segment
		(start 312.639202 -306.648104)
		(end 312.445908 -306.841398)
		(width 0.18288)
		(layer "In2.Cu")
		(net "M_B_CPU0_SA_DQ<7>")
	)
	(segment
		(start 299.795184 -306.587144)
		(end 299.61205 -306.770278)
		(width 0.18288)
		(layer "In2.Cu")
		(net "M_B_CPU0_SA_DQ<7>")
	)
	(segment
		(start 334.987646 -272.955004)
		(end 334.972914 -272.96364)
		(width 0.088646)
		(layer "In2.Cu")
		(net "M_B_CPU0_SA_DQ<7>")
	)
	(segment
		(start 306.046124 -306.526946)
		(end 305.700176 -306.872894)
		(width 0.18288)
		(layer "In2.Cu")
		(net "M_B_CPU0_SA_DQ<7>")
	)
	(segment
		(start 318.633094 -304.175414)
		(end 315.148976 -307.659532)
		(width 0.18288)
		(layer "In2.Cu")
		(net "M_B_CPU0_SA_DQ<7>")
	)
	(segment
		(start 301.799752 -306.577238)
		(end 301.639732 -306.417218)
		(width 0.18288)
		(layer "In2.Cu")
		(net "M_B_CPU0_SA_DQ<7>")
	)
	(segment
		(start 333.563214 -273.777456)
		(end 333.547212 -273.786854)
		(width 0.088646)
		(layer "In2.Cu")
		(net "M_B_CPU0_SA_DQ<7>")
	)
	(segment
		(start 325.142352 -286.95777)
		(end 320.42481 -298.34713)
		(width 0.18288)
		(layer "In2.Cu")
		(net "M_B_CPU0_SA_DQ<7>")
	)
	(segment
		(start 333.09306 -274.591272)
		(end 333.086964 -274.594828)
		(width 0.088646)
		(layer "In2.Cu")
		(net "M_B_CPU0_SA_DQ<7>")
	)
	(segment
		(start 327.954386 -284.145736)
		(end 325.142352 -286.95777)
		(width 0.18288)
		(layer "In2.Cu")
		(net "M_B_CPU0_SA_DQ<7>")
	)
	(segment
		(start 332.505812 -277.12289)
		(end 332.336648 -277.292054)
		(width 0.088646)
		(layer "In2.Cu")
		(net "M_B_CPU0_SA_DQ<7>")
	)
	(segment
		(start 319.849754 -301.238158)
		(end 318.633094 -304.175414)
		(width 0.18288)
		(layer "In2.Cu")
		(net "M_B_CPU0_SA_DQ<7>")
	)
	(segment
		(start 314.17387 -307.659532)
		(end 313.909456 -307.395118)
		(width 0.18288)
		(layer "In2.Cu")
		(net "M_B_CPU0_SA_DQ<7>")
	)
	(segment
		(start 308.220872 -308.101746)
		(end 308.220872 -307.608986)
		(width 0.18288)
		(layer "In2.Cu")
		(net "M_B_CPU0_SA_DQ<7>")
	)
	(segment
		(start 303.02962 -306.316888)
		(end 302.76927 -306.577238)
		(width 0.18288)
		(layer "In2.Cu")
		(net "M_B_CPU0_SA_DQ<7>")
	)
	(segment
		(start 303.02962 -304.676048)
		(end 303.02962 -306.316888)
		(width 0.18288)
		(layer "In2.Cu")
		(net "M_B_CPU0_SA_DQ<7>")
	)
	(segment
		(start 300.67758 -306.587144)
		(end 299.795184 -306.587144)
		(width 0.18288)
		(layer "In2.Cu")
		(net "M_B_CPU0_SA_DQ<7>")
	)
	(segment
		(start 299.61205 -306.770278)
		(end 299.61205 -307.23459)
		(width 0.18288)
		(layer "In2.Cu")
		(net "M_B_CPU0_SA_DQ<7>")
	)
	(segment
		(start 302.76927 -306.577238)
		(end 301.799752 -306.577238)
		(width 0.18288)
		(layer "In2.Cu")
		(net "M_B_CPU0_SA_DQ<7>")
	)
	(segment
		(start 299.61205 -307.23459)
		(end 299.029882 -307.816758)
		(width 0.18288)
		(layer "In2.Cu")
		(net "M_B_CPU0_SA_DQ<7>")
	)
	(arc
		(start 333.280512 -274.266914)
		(mid 333.232833 -274.449814)
		(end 333.10195 -274.586192)
		(width 0.088646)
		(layer "In2.Cu")
		(net "M_B_CPU0_SA_DQ<7>")
	)
	(arc
		(start 334.972914 -272.96364)
		(mid 334.785716 -273.013783)
		(end 334.598518 -272.96364)
		(width 0.088646)
		(layer "In2.Cu")
		(net "M_B_CPU0_SA_DQ<7>")
	)
	(arc
		(start 337.417664 -272.96364)
		(mid 337.141105 -272.887897)
		(end 336.862928 -272.957544)
		(width 0.088646)
		(layer "In2.Cu")
		(net "M_B_CPU0_SA_DQ<7>")
	)
	(arc
		(start 332.340458 -275.8948)
		(mid 332.414449 -276.174366)
		(end 332.617064 -276.380702)
		(width 0.088646)
		(layer "In2.Cu")
		(net "M_B_CPU0_SA_DQ<7>")
	)
	(arc
		(start 333.750666 -273.453098)
		(mid 333.702987 -273.635998)
		(end 333.572104 -273.772376)
		(width 0.088646)
		(layer "In2.Cu")
		(net "M_B_CPU0_SA_DQ<7>")
	)
	(arc
		(start 333.547212 -273.786854)
		(mid 333.351495 -273.992271)
		(end 333.280258 -274.266914)
		(width 0.088646)
		(layer "In2.Cu")
		(net "M_B_CPU0_SA_DQ<7>")
	)
	(arc
		(start 335.912714 -272.96364)
		(mid 335.725516 -273.013783)
		(end 335.538318 -272.96364)
		(width 0.088646)
		(layer "In2.Cu")
		(net "M_B_CPU0_SA_DQ<7>")
	)
	(arc
		(start 336.852514 -272.96364)
		(mid 336.665316 -273.013783)
		(end 336.478118 -272.96364)
		(width 0.088646)
		(layer "In2.Cu")
		(net "M_B_CPU0_SA_DQ<7>")
	)
	(arc
		(start 334.033114 -272.96364)
		(mid 333.828779 -273.166245)
		(end 333.750666 -273.443192)
		(width 0.088646)
		(layer "In2.Cu")
		(net "M_B_CPU0_SA_DQ<7>")
	)
	(arc
		(start 335.538318 -272.96364)
		(mid 335.264119 -272.887805)
		(end 334.987646 -272.955004)
		(width 0.088646)
		(layer "In2.Cu")
		(net "M_B_CPU0_SA_DQ<7>")
	)
	(arc
		(start 333.086964 -274.594828)
		(mid 332.884377 -274.801179)
		(end 332.810358 -275.08073)
		(width 0.088646)
		(layer "In2.Cu")
		(net "M_B_CPU0_SA_DQ<7>")
	)
	(arc
		(start 332.810358 -275.08073)
		(mid 332.762679 -275.26363)
		(end 332.631796 -275.400008)
		(width 0.088646)
		(layer "In2.Cu")
		(net "M_B_CPU0_SA_DQ<7>")
	)
	(arc
		(start 332.63205 -276.389338)
		(mid 332.810647 -276.708616)
		(end 332.63205 -277.027894)
		(width 0.088646)
		(layer "In2.Cu")
		(net "M_B_CPU0_SA_DQ<7>")
	)
	(arc
		(start 336.478118 -272.96364)
		(mid 336.203919 -272.887805)
		(end 335.927446 -272.955004)
		(width 0.088646)
		(layer "In2.Cu")
		(net "M_B_CPU0_SA_DQ<7>")
	)
	(arc
		(start 337.696556 -273.38782)
		(mid 337.607427 -273.142645)
		(end 337.417664 -272.96364)
		(width 0.088646)
		(layer "In2.Cu")
		(net "M_B_CPU0_SA_DQ<7>")
	)
	(arc
		(start 332.622906 -275.405088)
		(mid 332.42062 -275.604069)
		(end 332.340458 -275.876258)
		(width 0.088646)
		(layer "In2.Cu")
		(net "M_B_CPU0_SA_DQ<7>")
	)
	(arc
		(start 332.62316 -277.032974)
		(mid 332.561527 -277.074071)
		(end 332.505812 -277.12289)
		(width 0.088646)
		(layer "In2.Cu")
		(net "M_B_CPU0_SA_DQ<7>")
	)
	(arc
		(start 334.598518 -272.96364)
		(mid 334.315816 -272.887864)
		(end 334.033114 -272.96364)
		(width 0.088646)
		(layer "In2.Cu")
		(net "M_B_CPU0_SA_DQ<7>")
	)
	(segment
		(start 338.544916 -273.730974)
		(end 338.544916 -274.26666)
		(width 0.20066)
		(layer "F.Cu")
		(net "M_B_CPU0_SA_DQ<6>")
	)
	(segment
		(start 295.000426 -309.091838)
		(end 292.940486 -309.091838)
		(width 0.1016)
		(layer "F.Cu")
		(net "M_B_CPU0_SA_DQ<6>")
	)
	(segment
		(start 291.502846 -309.51678)
		(end 290.355782 -309.51678)
		(width 0.20066)
		(layer "F.Cu")
		(net "M_B_CPU0_SA_DQ<6>")
	)
	(segment
		(start 295.777158 -309.56123)
		(end 295.777158 -309.235602)
		(width 0.20066)
		(layer "F.Cu")
		(net "M_B_CPU0_SA_DQ<6>")
	)
	(segment
		(start 296.584878 -309.51678)
		(end 296.373042 -309.728616)
		(width 0.20066)
		(layer "F.Cu")
		(net "M_B_CPU0_SA_DQ<6>")
	)
	(segment
		(start 297.899582 -309.51678)
		(end 296.584878 -309.51678)
		(width 0.20066)
		(layer "F.Cu")
		(net "M_B_CPU0_SA_DQ<6>")
	)
	(segment
		(start 292.67531 -309.081678)
		(end 291.937948 -309.081678)
		(width 0.20066)
		(layer "F.Cu")
		(net "M_B_CPU0_SA_DQ<6>")
	)
	(segment
		(start 338.544916 -274.26666)
		(end 338.544662 -274.266914)
		(width 0.20066)
		(layer "F.Cu")
		(net "M_B_CPU0_SA_DQ<6>")
	)
	(segment
		(start 296.373042 -309.728616)
		(end 295.944544 -309.728616)
		(width 0.20066)
		(layer "F.Cu")
		(net "M_B_CPU0_SA_DQ<6>")
	)
	(segment
		(start 291.937948 -309.081678)
		(end 291.502846 -309.51678)
		(width 0.20066)
		(layer "F.Cu")
		(net "M_B_CPU0_SA_DQ<6>")
	)
	(segment
		(start 295.944544 -309.728616)
		(end 295.777158 -309.56123)
		(width 0.20066)
		(layer "F.Cu")
		(net "M_B_CPU0_SA_DQ<6>")
	)
	(segment
		(start 295.777158 -309.235602)
		(end 295.633394 -309.091838)
		(width 0.20066)
		(layer "F.Cu")
		(net "M_B_CPU0_SA_DQ<6>")
	)
	(segment
		(start 299.029882 -309.51678)
		(end 297.899582 -309.51678)
		(width 0.20066)
		(layer "F.Cu")
		(net "M_B_CPU0_SA_DQ<6>")
	)
	(segment
		(start 292.940486 -309.091838)
		(end 292.68547 -309.091838)
		(width 0.101854)
		(layer "F.Cu")
		(net "M_B_CPU0_SA_DQ<6>")
	)
	(segment
		(start 292.68547 -309.091838)
		(end 292.67531 -309.081678)
		(width 0.101854)
		(layer "F.Cu")
		(net "M_B_CPU0_SA_DQ<6>")
	)
	(segment
		(start 295.633394 -309.091838)
		(end 295.000426 -309.091838)
		(width 0.20066)
		(layer "F.Cu")
		(net "M_B_CPU0_SA_DQ<6>")
	)
	(segment
		(start 329.793346 -282.361894)
		(end 329.145138 -283.926788)
		(width 0.18288)
		(layer "In2.Cu")
		(net "M_B_CPU0_SA_DQ<6>")
	)
	(segment
		(start 305.716432 -308.459124)
		(end 305.523392 -308.266084)
		(width 0.18288)
		(layer "In2.Cu")
		(net "M_B_CPU0_SA_DQ<6>")
	)
	(segment
		(start 302.54829 -308.282086)
		(end 302.316388 -308.513988)
		(width 0.18288)
		(layer "In2.Cu")
		(net "M_B_CPU0_SA_DQ<6>")
	)
	(segment
		(start 312.847482 -308.746398)
		(end 312.473848 -309.120032)
		(width 0.18288)
		(layer "In2.Cu")
		(net "M_B_CPU0_SA_DQ<6>")
	)
	(segment
		(start 311.380124 -309.120032)
		(end 310.289194 -310.210962)
		(width 0.18288)
		(layer "In2.Cu")
		(net "M_B_CPU0_SA_DQ<6>")
	)
	(segment
		(start 309.465472 -309.66029)
		(end 308.411626 -309.66029)
		(width 0.18288)
		(layer "In2.Cu")
		(net "M_B_CPU0_SA_DQ<6>")
	)
	(segment
		(start 332.699614 -277.973282)
		(end 332.446122 -278.226774)
		(width 0.088646)
		(layer "In2.Cu")
		(net "M_B_CPU0_SA_DQ<6>")
	)
	(segment
		(start 301.903638 -309.42153)
		(end 300.824392 -309.42153)
		(width 0.18288)
		(layer "In2.Cu")
		(net "M_B_CPU0_SA_DQ<6>")
	)
	(segment
		(start 305.205892 -308.266084)
		(end 305.012852 -308.459124)
		(width 0.18288)
		(layer "In2.Cu")
		(net "M_B_CPU0_SA_DQ<6>")
	)
	(segment
		(start 303.918874 -310.246522)
		(end 303.713134 -310.452262)
		(width 0.18288)
		(layer "In2.Cu")
		(net "M_B_CPU0_SA_DQ<6>")
	)
	(segment
		(start 299.526452 -309.02021)
		(end 299.029882 -309.51678)
		(width 0.18288)
		(layer "In2.Cu")
		(net "M_B_CPU0_SA_DQ<6>")
	)
	(segment
		(start 329.793346 -280.87955)
		(end 329.793346 -282.361894)
		(width 0.18288)
		(layer "In2.Cu")
		(net "M_B_CPU0_SA_DQ<6>")
	)
	(segment
		(start 333.280258 -277.602696)
		(end 332.909672 -277.973282)
		(width 0.088646)
		(layer "In2.Cu")
		(net "M_B_CPU0_SA_DQ<6>")
	)
	(segment
		(start 305.909472 -309.127906)
		(end 305.716432 -308.934866)
		(width 0.18288)
		(layer "In2.Cu")
		(net "M_B_CPU0_SA_DQ<6>")
	)
	(segment
		(start 307.126386 -310.22417)
		(end 306.798726 -309.89651)
		(width 0.18288)
		(layer "In2.Cu")
		(net "M_B_CPU0_SA_DQ<6>")
	)
	(segment
		(start 334.03286 -274.591272)
		(end 334.026764 -274.594828)
		(width 0.088646)
		(layer "In2.Cu")
		(net "M_B_CPU0_SA_DQ<6>")
	)
	(segment
		(start 302.316388 -309.00878)
		(end 301.903638 -309.42153)
		(width 0.18288)
		(layer "In2.Cu")
		(net "M_B_CPU0_SA_DQ<6>")
	)
	(segment
		(start 335.457292 -273.769074)
		(end 335.44256 -273.777456)
		(width 0.088646)
		(layer "In2.Cu")
		(net "M_B_CPU0_SA_DQ<6>")
	)
	(segment
		(start 314.88126 -309.366412)
		(end 314.167266 -309.366412)
		(width 0.18288)
		(layer "In2.Cu")
		(net "M_B_CPU0_SA_DQ<6>")
	)
	(segment
		(start 333.56296 -276.384258)
		(end 333.57185 -276.389338)
		(width 0.088646)
		(layer "In2.Cu")
		(net "M_B_CPU0_SA_DQ<6>")
	)
	(segment
		(start 306.798726 -309.89651)
		(end 306.798726 -309.31612)
		(width 0.18288)
		(layer "In2.Cu")
		(net "M_B_CPU0_SA_DQ<6>")
	)
	(segment
		(start 333.571596 -275.400008)
		(end 333.562706 -275.405088)
		(width 0.088646)
		(layer "In2.Cu")
		(net "M_B_CPU0_SA_DQ<6>")
	)
	(segment
		(start 303.349152 -310.452262)
		(end 303.105566 -310.208676)
		(width 0.18288)
		(layer "In2.Cu")
		(net "M_B_CPU0_SA_DQ<6>")
	)
	(segment
		(start 320.825114 -301.543212)
		(end 319.495678 -304.751994)
		(width 0.18288)
		(layer "In2.Cu")
		(net "M_B_CPU0_SA_DQ<6>")
	)
	(segment
		(start 329.145138 -283.926788)
		(end 328.793856 -284.774894)
		(width 0.18288)
		(layer "In2.Cu")
		(net "M_B_CPU0_SA_DQ<6>")
	)
	(segment
		(start 305.012852 -308.459124)
		(end 305.012852 -308.934866)
		(width 0.18288)
		(layer "In2.Cu")
		(net "M_B_CPU0_SA_DQ<6>")
	)
	(segment
		(start 333.560166 -276.382734)
		(end 333.56296 -276.384258)
		(width 0.088646)
		(layer "In2.Cu")
		(net "M_B_CPU0_SA_DQ<6>")
	)
	(segment
		(start 303.105566 -310.208676)
		(end 303.105566 -308.475126)
		(width 0.18288)
		(layer "In2.Cu")
		(net "M_B_CPU0_SA_DQ<6>")
	)
	(segment
		(start 328.793856 -284.774894)
		(end 325.994014 -287.574736)
		(width 0.18288)
		(layer "In2.Cu")
		(net "M_B_CPU0_SA_DQ<6>")
	)
	(segment
		(start 334.513428 -273.77136)
		(end 334.503014 -273.777456)
		(width 0.088646)
		(layer "In2.Cu")
		(net "M_B_CPU0_SA_DQ<6>")
	)
	(segment
		(start 303.918874 -309.320946)
		(end 303.918874 -310.246522)
		(width 0.18288)
		(layer "In2.Cu")
		(net "M_B_CPU0_SA_DQ<6>")
	)
	(segment
		(start 308.411626 -309.66029)
		(end 307.847746 -310.22417)
		(width 0.18288)
		(layer "In2.Cu")
		(net "M_B_CPU0_SA_DQ<6>")
	)
	(segment
		(start 335.457546 -273.76882)
		(end 335.457292 -273.769074)
		(width 0.088646)
		(layer "In2.Cu")
		(net "M_B_CPU0_SA_DQ<6>")
	)
	(segment
		(start 304.111914 -309.127906)
		(end 303.918874 -309.320946)
		(width 0.18288)
		(layer "In2.Cu")
		(net "M_B_CPU0_SA_DQ<6>")
	)
	(segment
		(start 312.473848 -309.120032)
		(end 311.380124 -309.120032)
		(width 0.18288)
		(layer "In2.Cu")
		(net "M_B_CPU0_SA_DQ<6>")
	)
	(segment
		(start 306.610512 -309.127906)
		(end 305.909472 -309.127906)
		(width 0.18288)
		(layer "In2.Cu")
		(net "M_B_CPU0_SA_DQ<6>")
	)
	(segment
		(start 306.798726 -309.31612)
		(end 306.610512 -309.127906)
		(width 0.18288)
		(layer "In2.Cu")
		(net "M_B_CPU0_SA_DQ<6>")
	)
	(segment
		(start 310.016144 -310.210962)
		(end 309.465472 -309.66029)
		(width 0.18288)
		(layer "In2.Cu")
		(net "M_B_CPU0_SA_DQ<6>")
	)
	(segment
		(start 333.280258 -277.508462)
		(end 333.280258 -277.602696)
		(width 0.088646)
		(layer "In2.Cu")
		(net "M_B_CPU0_SA_DQ<6>")
	)
	(segment
		(start 303.105566 -308.475126)
		(end 302.912526 -308.282086)
		(width 0.18288)
		(layer "In2.Cu")
		(net "M_B_CPU0_SA_DQ<6>")
	)
	(segment
		(start 338.231734 -274.266914)
		(end 338.166456 -274.201636)
		(width 0.088646)
		(layer "In2.Cu")
		(net "M_B_CPU0_SA_DQ<6>")
	)
	(segment
		(start 305.716432 -308.934866)
		(end 305.716432 -308.459124)
		(width 0.18288)
		(layer "In2.Cu")
		(net "M_B_CPU0_SA_DQ<6>")
	)
	(segment
		(start 337.332828 -273.77136)
		(end 337.322414 -273.777456)
		(width 0.088646)
		(layer "In2.Cu")
		(net "M_B_CPU0_SA_DQ<6>")
	)
	(segment
		(start 333.556864 -276.380702)
		(end 333.560166 -276.382734)
		(width 0.088646)
		(layer "In2.Cu")
		(net "M_B_CPU0_SA_DQ<6>")
	)
	(segment
		(start 300.423072 -309.02021)
		(end 299.526452 -309.02021)
		(width 0.18288)
		(layer "In2.Cu")
		(net "M_B_CPU0_SA_DQ<6>")
	)
	(segment
		(start 314.167266 -309.366412)
		(end 313.547252 -308.746398)
		(width 0.18288)
		(layer "In2.Cu")
		(net "M_B_CPU0_SA_DQ<6>")
	)
	(segment
		(start 338.544662 -274.266914)
		(end 338.231734 -274.266914)
		(width 0.088646)
		(layer "In2.Cu")
		(net "M_B_CPU0_SA_DQ<6>")
	)
	(segment
		(start 305.012852 -308.934866)
		(end 304.819812 -309.127906)
		(width 0.18288)
		(layer "In2.Cu")
		(net "M_B_CPU0_SA_DQ<6>")
	)
	(segment
		(start 302.912526 -308.282086)
		(end 302.54829 -308.282086)
		(width 0.18288)
		(layer "In2.Cu")
		(net "M_B_CPU0_SA_DQ<6>")
	)
	(segment
		(start 333.57185 -277.027894)
		(end 333.56296 -277.032974)
		(width 0.088646)
		(layer "In2.Cu")
		(net "M_B_CPU0_SA_DQ<6>")
	)
	(segment
		(start 336.397346 -273.76882)
		(end 336.382614 -273.777456)
		(width 0.088646)
		(layer "In2.Cu")
		(net "M_B_CPU0_SA_DQ<6>")
	)
	(segment
		(start 313.547252 -308.746398)
		(end 312.847482 -308.746398)
		(width 0.18288)
		(layer "In2.Cu")
		(net "M_B_CPU0_SA_DQ<6>")
	)
	(segment
		(start 305.523392 -308.266084)
		(end 305.205892 -308.266084)
		(width 0.18288)
		(layer "In2.Cu")
		(net "M_B_CPU0_SA_DQ<6>")
	)
	(segment
		(start 321.39509 -298.678346)
		(end 320.825114 -301.543212)
		(width 0.18288)
		(layer "In2.Cu")
		(net "M_B_CPU0_SA_DQ<6>")
	)
	(segment
		(start 300.824392 -309.42153)
		(end 300.423072 -309.02021)
		(width 0.18288)
		(layer "In2.Cu")
		(net "M_B_CPU0_SA_DQ<6>")
	)
	(segment
		(start 325.994014 -287.574736)
		(end 321.39509 -298.678346)
		(width 0.18288)
		(layer "In2.Cu")
		(net "M_B_CPU0_SA_DQ<6>")
	)
	(segment
		(start 307.847746 -310.22417)
		(end 307.126386 -310.22417)
		(width 0.18288)
		(layer "In2.Cu")
		(net "M_B_CPU0_SA_DQ<6>")
	)
	(segment
		(start 319.495678 -304.751994)
		(end 314.88126 -309.366412)
		(width 0.18288)
		(layer "In2.Cu")
		(net "M_B_CPU0_SA_DQ<6>")
	)
	(segment
		(start 334.04175 -274.586192)
		(end 334.03286 -274.591272)
		(width 0.088646)
		(layer "In2.Cu")
		(net "M_B_CPU0_SA_DQ<6>")
	)
	(segment
		(start 333.280258 -275.876258)
		(end 333.280258 -275.8948)
		(width 0.088646)
		(layer "In2.Cu")
		(net "M_B_CPU0_SA_DQ<6>")
	)
	(segment
		(start 332.909672 -277.973282)
		(end 332.699614 -277.973282)
		(width 0.088646)
		(layer "In2.Cu")
		(net "M_B_CPU0_SA_DQ<6>")
	)
	(segment
		(start 302.316388 -308.513988)
		(end 302.316388 -309.00878)
		(width 0.18288)
		(layer "In2.Cu")
		(net "M_B_CPU0_SA_DQ<6>")
	)
	(segment
		(start 304.819812 -309.127906)
		(end 304.111914 -309.127906)
		(width 0.18288)
		(layer "In2.Cu")
		(net "M_B_CPU0_SA_DQ<6>")
	)
	(segment
		(start 334.503014 -273.777456)
		(end 334.496918 -273.781012)
		(width 0.088646)
		(layer "In2.Cu")
		(net "M_B_CPU0_SA_DQ<6>")
	)
	(segment
		(start 303.713134 -310.452262)
		(end 303.349152 -310.452262)
		(width 0.18288)
		(layer "In2.Cu")
		(net "M_B_CPU0_SA_DQ<6>")
	)
	(segment
		(start 332.446122 -278.226774)
		(end 329.793346 -280.87955)
		(width 0.18288)
		(layer "In2.Cu")
		(net "M_B_CPU0_SA_DQ<6>")
	)
	(segment
		(start 310.289194 -310.210962)
		(end 310.016144 -310.210962)
		(width 0.18288)
		(layer "In2.Cu")
		(net "M_B_CPU0_SA_DQ<6>")
	)
	(arc
		(start 334.496918 -273.781012)
		(mid 334.294331 -273.987363)
		(end 334.220312 -274.266914)
		(width 0.088646)
		(layer "In2.Cu")
		(net "M_B_CPU0_SA_DQ<6>")
	)
	(arc
		(start 335.068164 -273.777456)
		(mid 334.791605 -273.701713)
		(end 334.513428 -273.77136)
		(width 0.088646)
		(layer "In2.Cu")
		(net "M_B_CPU0_SA_DQ<6>")
	)
	(arc
		(start 336.008218 -273.777456)
		(mid 335.734019 -273.701621)
		(end 335.457546 -273.76882)
		(width 0.088646)
		(layer "In2.Cu")
		(net "M_B_CPU0_SA_DQ<6>")
	)
	(arc
		(start 337.322414 -273.777456)
		(mid 337.135216 -273.827599)
		(end 336.948018 -273.777456)
		(width 0.088646)
		(layer "In2.Cu")
		(net "M_B_CPU0_SA_DQ<6>")
	)
	(arc
		(start 334.026764 -274.594828)
		(mid 333.824177 -274.801179)
		(end 333.750158 -275.08073)
		(width 0.088646)
		(layer "In2.Cu")
		(net "M_B_CPU0_SA_DQ<6>")
	)
	(arc
		(start 335.44256 -273.777456)
		(mid 335.255362 -273.827599)
		(end 335.068164 -273.777456)
		(width 0.088646)
		(layer "In2.Cu")
		(net "M_B_CPU0_SA_DQ<6>")
	)
	(arc
		(start 336.948018 -273.777456)
		(mid 336.673819 -273.701621)
		(end 336.397346 -273.76882)
		(width 0.088646)
		(layer "In2.Cu")
		(net "M_B_CPU0_SA_DQ<6>")
	)
	(arc
		(start 333.57185 -276.389338)
		(mid 333.750447 -276.708616)
		(end 333.57185 -277.027894)
		(width 0.088646)
		(layer "In2.Cu")
		(net "M_B_CPU0_SA_DQ<6>")
	)
	(arc
		(start 333.280258 -275.8948)
		(mid 333.354249 -276.174366)
		(end 333.556864 -276.380702)
		(width 0.088646)
		(layer "In2.Cu")
		(net "M_B_CPU0_SA_DQ<6>")
	)
	(arc
		(start 333.56296 -277.032974)
		(mid 333.359479 -277.233778)
		(end 333.280258 -277.508462)
		(width 0.088646)
		(layer "In2.Cu")
		(net "M_B_CPU0_SA_DQ<6>")
	)
	(arc
		(start 334.220312 -274.266914)
		(mid 334.172633 -274.449814)
		(end 334.04175 -274.586192)
		(width 0.088646)
		(layer "In2.Cu")
		(net "M_B_CPU0_SA_DQ<6>")
	)
	(arc
		(start 333.562706 -275.405088)
		(mid 333.36042 -275.604069)
		(end 333.280258 -275.876258)
		(width 0.088646)
		(layer "In2.Cu")
		(net "M_B_CPU0_SA_DQ<6>")
	)
	(arc
		(start 338.166456 -274.201636)
		(mid 338.077327 -273.956461)
		(end 337.887564 -273.777456)
		(width 0.088646)
		(layer "In2.Cu")
		(net "M_B_CPU0_SA_DQ<6>")
	)
	(arc
		(start 336.382614 -273.777456)
		(mid 336.195416 -273.827599)
		(end 336.008218 -273.777456)
		(width 0.088646)
		(layer "In2.Cu")
		(net "M_B_CPU0_SA_DQ<6>")
	)
	(arc
		(start 333.750158 -275.08073)
		(mid 333.702479 -275.26363)
		(end 333.571596 -275.400008)
		(width 0.088646)
		(layer "In2.Cu")
		(net "M_B_CPU0_SA_DQ<6>")
	)
	(arc
		(start 337.887564 -273.777456)
		(mid 337.611005 -273.701713)
		(end 337.332828 -273.77136)
		(width 0.088646)
		(layer "In2.Cu")
		(net "M_B_CPU0_SA_DQ<6>")
	)
	(segment
		(start 288.46018 -308.723538)
		(end 288.305748 -308.87797)
		(width 0.20066)
		(layer "F.Cu")
		(net "M_B_CPU0_SA_DQ<5>")
	)
	(segment
		(start 291.225986 -308.2417)
		(end 289.240468 -308.2417)
		(width 0.1016)
		(layer "F.Cu")
		(net "M_B_CPU0_SA_DQ<5>")
	)
	(segment
		(start 294.904414 -308.666642)
		(end 293.799514 -308.666642)
		(width 0.20066)
		(layer "F.Cu")
		(net "M_B_CPU0_SA_DQ<5>")
	)
	(segment
		(start 291.556694 -308.2417)
		(end 291.225986 -308.2417)
		(width 0.101854)
		(layer "F.Cu")
		(net "M_B_CPU0_SA_DQ<5>")
	)
	(segment
		(start 288.46018 -308.39537)
		(end 288.46018 -308.723538)
		(width 0.20066)
		(layer "F.Cu")
		(net "M_B_CPU0_SA_DQ<5>")
	)
	(segment
		(start 287.589976 -308.666642)
		(end 286.255714 -308.666642)
		(width 0.20066)
		(layer "F.Cu")
		(net "M_B_CPU0_SA_DQ<5>")
	)
	(segment
		(start 288.62274 -308.23281)
		(end 288.46018 -308.39537)
		(width 0.20066)
		(layer "F.Cu")
		(net "M_B_CPU0_SA_DQ<5>")
	)
	(segment
		(start 293.799514 -308.666642)
		(end 292.160198 -308.666642)
		(width 0.20066)
		(layer "F.Cu")
		(net "M_B_CPU0_SA_DQ<5>")
	)
	(segment
		(start 292.160198 -308.666642)
		(end 291.735256 -308.2417)
		(width 0.20066)
		(layer "F.Cu")
		(net "M_B_CPU0_SA_DQ<5>")
	)
	(segment
		(start 287.801304 -308.87797)
		(end 287.589976 -308.666642)
		(width 0.20066)
		(layer "F.Cu")
		(net "M_B_CPU0_SA_DQ<5>")
	)
	(segment
		(start 337.134962 -272.917158)
		(end 337.134962 -273.453098)
		(width 0.20066)
		(layer "F.Cu")
		(net "M_B_CPU0_SA_DQ<5>")
	)
	(segment
		(start 289.231578 -308.23281)
		(end 288.62274 -308.23281)
		(width 0.20066)
		(layer "F.Cu")
		(net "M_B_CPU0_SA_DQ<5>")
	)
	(segment
		(start 288.305748 -308.87797)
		(end 287.801304 -308.87797)
		(width 0.20066)
		(layer "F.Cu")
		(net "M_B_CPU0_SA_DQ<5>")
	)
	(segment
		(start 289.240468 -308.2417)
		(end 289.231578 -308.23281)
		(width 0.1016)
		(layer "F.Cu")
		(net "M_B_CPU0_SA_DQ<5>")
	)
	(segment
		(start 291.735256 -308.2417)
		(end 291.556694 -308.2417)
		(width 0.20066)
		(layer "F.Cu")
		(net "M_B_CPU0_SA_DQ<5>")
	)
	(segment
		(start 296.478706 -308.223666)
		(end 296.285666 -308.030626)
		(width 0.18288)
		(layer "In2.Cu")
		(net "M_B_CPU0_SA_DQ<5>")
	)
	(segment
		(start 333.191104 -274.754848)
		(end 333.18831 -274.756372)
		(width 0.088646)
		(layer "In2.Cu")
		(net "M_B_CPU0_SA_DQ<5>")
	)
	(segment
		(start 302.312832 -307.259736)
		(end 301.938944 -307.633624)
		(width 0.18288)
		(layer "In2.Cu")
		(net "M_B_CPU0_SA_DQ<5>")
	)
	(segment
		(start 304.02657 -307.661818)
		(end 303.201832 -307.661818)
		(width 0.18288)
		(layer "In2.Cu")
		(net "M_B_CPU0_SA_DQ<5>")
	)
	(segment
		(start 312.058558 -308.130702)
		(end 311.439814 -308.130702)
		(width 0.18288)
		(layer "In2.Cu")
		(net "M_B_CPU0_SA_DQ<5>")
	)
	(segment
		(start 299.62094 -308.45125)
		(end 299.41139 -308.2417)
		(width 0.18288)
		(layer "In2.Cu")
		(net "M_B_CPU0_SA_DQ<5>")
	)
	(segment
		(start 320.912236 -298.5008)
		(end 320.337942 -301.388272)
		(width 0.18288)
		(layer "In2.Cu")
		(net "M_B_CPU0_SA_DQ<5>")
	)
	(segment
		(start 332.71841 -276.219158)
		(end 332.724506 -276.222714)
		(width 0.088646)
		(layer "In2.Cu")
		(net "M_B_CPU0_SA_DQ<5>")
	)
	(segment
		(start 301.938944 -307.633624)
		(end 301.938944 -307.89245)
		(width 0.18288)
		(layer "In2.Cu")
		(net "M_B_CPU0_SA_DQ<5>")
	)
	(segment
		(start 337.44789 -273.453098)
		(end 337.50504 -273.395948)
		(width 0.088646)
		(layer "In2.Cu")
		(net "M_B_CPU0_SA_DQ<5>")
	)
	(segment
		(start 325.559928 -287.28035)
		(end 320.912236 -298.5008)
		(width 0.18288)
		(layer "In2.Cu")
		(net "M_B_CPU0_SA_DQ<5>")
	)
	(segment
		(start 329.123294 -282.651708)
		(end 328.36993 -284.470348)
		(width 0.18288)
		(layer "In2.Cu")
		(net "M_B_CPU0_SA_DQ<5>")
	)
	(segment
		(start 298.027598 -309.039514)
		(end 297.659552 -309.039514)
		(width 0.18288)
		(layer "In2.Cu")
		(net "M_B_CPU0_SA_DQ<5>")
	)
	(segment
		(start 304.286666 -307.401722)
		(end 304.02657 -307.661818)
		(width 0.18288)
		(layer "In2.Cu")
		(net "M_B_CPU0_SA_DQ<5>")
	)
	(segment
		(start 336.007964 -273.12874)
		(end 335.993232 -273.137376)
		(width 0.088646)
		(layer "In2.Cu")
		(net "M_B_CPU0_SA_DQ<5>")
	)
	(segment
		(start 296.285666 -307.79847)
		(end 296.092626 -307.60543)
		(width 0.18288)
		(layer "In2.Cu")
		(net "M_B_CPU0_SA_DQ<5>")
	)
	(segment
		(start 332.70952 -276.214078)
		(end 332.71841 -276.219158)
		(width 0.088646)
		(layer "In2.Cu")
		(net "M_B_CPU0_SA_DQ<5>")
	)
	(segment
		(start 310.74995 -308.820566)
		(end 310.03875 -308.820566)
		(width 0.18288)
		(layer "In2.Cu")
		(net "M_B_CPU0_SA_DQ<5>")
	)
	(segment
		(start 298.187618 -308.40172)
		(end 298.187618 -308.879494)
		(width 0.18288)
		(layer "In2.Cu")
		(net "M_B_CPU0_SA_DQ<5>")
	)
	(segment
		(start 297.47972 -308.416706)
		(end 297.28668 -308.223666)
		(width 0.18288)
		(layer "In2.Cu")
		(net "M_B_CPU0_SA_DQ<5>")
	)
	(segment
		(start 300.94301 -307.729382)
		(end 300.221142 -308.45125)
		(width 0.18288)
		(layer "In2.Cu")
		(net "M_B_CPU0_SA_DQ<5>")
	)
	(segment
		(start 332.71841 -277.198328)
		(end 332.70952 -277.203408)
		(width 0.088646)
		(layer "In2.Cu")
		(net "M_B_CPU0_SA_DQ<5>")
	)
	(segment
		(start 295.462706 -308.473602)
		(end 295.269666 -308.666642)
		(width 0.18288)
		(layer "In2.Cu")
		(net "M_B_CPU0_SA_DQ<5>")
	)
	(segment
		(start 336.947764 -273.12874)
		(end 336.933032 -273.137376)
		(width 0.088646)
		(layer "In2.Cu")
		(net "M_B_CPU0_SA_DQ<5>")
	)
	(segment
		(start 333.18831 -274.756372)
		(end 333.17942 -274.761452)
		(width 0.088646)
		(layer "In2.Cu")
		(net "M_B_CPU0_SA_DQ<5>")
	)
	(segment
		(start 301.789846 -308.041548)
		(end 301.50308 -308.041548)
		(width 0.18288)
		(layer "In2.Cu")
		(net "M_B_CPU0_SA_DQ<5>")
	)
	(segment
		(start 295.269666 -308.666642)
		(end 294.904414 -308.666642)
		(width 0.18288)
		(layer "In2.Cu")
		(net "M_B_CPU0_SA_DQ<5>")
	)
	(segment
		(start 298.347638 -308.2417)
		(end 298.187618 -308.40172)
		(width 0.18288)
		(layer "In2.Cu")
		(net "M_B_CPU0_SA_DQ<5>")
	)
	(segment
		(start 311.439814 -308.130702)
		(end 310.74995 -308.820566)
		(width 0.18288)
		(layer "In2.Cu")
		(net "M_B_CPU0_SA_DQ<5>")
	)
	(segment
		(start 306.333906 -307.401722)
		(end 304.286666 -307.401722)
		(width 0.18288)
		(layer "In2.Cu")
		(net "M_B_CPU0_SA_DQ<5>")
	)
	(segment
		(start 333.66456 -273.939)
		(end 333.658464 -273.942556)
		(width 0.088646)
		(layer "In2.Cu")
		(net "M_B_CPU0_SA_DQ<5>")
	)
	(segment
		(start 297.659552 -309.039514)
		(end 297.47972 -308.859682)
		(width 0.18288)
		(layer "In2.Cu")
		(net "M_B_CPU0_SA_DQ<5>")
	)
	(segment
		(start 303.201832 -307.661818)
		(end 302.79975 -307.259736)
		(width 0.18288)
		(layer "In2.Cu")
		(net "M_B_CPU0_SA_DQ<5>")
	)
	(segment
		(start 315.294518 -308.233572)
		(end 312.161428 -308.233572)
		(width 0.18288)
		(layer "In2.Cu")
		(net "M_B_CPU0_SA_DQ<5>")
	)
	(segment
		(start 308.044596 -309.112412)
		(end 306.333906 -307.401722)
		(width 0.18288)
		(layer "In2.Cu")
		(net "M_B_CPU0_SA_DQ<5>")
	)
	(segment
		(start 333.194406 -274.752816)
		(end 333.191104 -274.754848)
		(width 0.088646)
		(layer "In2.Cu")
		(net "M_B_CPU0_SA_DQ<5>")
	)
	(segment
		(start 297.28668 -308.223666)
		(end 296.478706 -308.223666)
		(width 0.18288)
		(layer "In2.Cu")
		(net "M_B_CPU0_SA_DQ<5>")
	)
	(segment
		(start 301.190914 -307.729382)
		(end 300.94301 -307.729382)
		(width 0.18288)
		(layer "In2.Cu")
		(net "M_B_CPU0_SA_DQ<5>")
	)
	(segment
		(start 328.36993 -284.470348)
		(end 325.559928 -287.28035)
		(width 0.18288)
		(layer "In2.Cu")
		(net "M_B_CPU0_SA_DQ<5>")
	)
	(segment
		(start 312.161428 -308.233572)
		(end 312.058558 -308.130702)
		(width 0.18288)
		(layer "In2.Cu")
		(net "M_B_CPU0_SA_DQ<5>")
	)
	(segment
		(start 329.447906 -280.730452)
		(end 329.447906 -281.867864)
		(width 0.18288)
		(layer "In2.Cu")
		(net "M_B_CPU0_SA_DQ<5>")
	)
	(segment
		(start 337.33105 -273.13382)
		(end 337.32216 -273.12874)
		(width 0.088646)
		(layer "In2.Cu")
		(net "M_B_CPU0_SA_DQ<5>")
	)
	(segment
		(start 301.938944 -307.89245)
		(end 301.789846 -308.041548)
		(width 0.18288)
		(layer "In2.Cu")
		(net "M_B_CPU0_SA_DQ<5>")
	)
	(segment
		(start 332.530196 -277.648162)
		(end 332.198726 -277.979632)
		(width 0.088646)
		(layer "In2.Cu")
		(net "M_B_CPU0_SA_DQ<5>")
	)
	(segment
		(start 296.092626 -307.60543)
		(end 295.655746 -307.60543)
		(width 0.18288)
		(layer "In2.Cu")
		(net "M_B_CPU0_SA_DQ<5>")
	)
	(segment
		(start 334.128618 -273.12874)
		(end 334.119728 -273.13382)
		(width 0.088646)
		(layer "In2.Cu")
		(net "M_B_CPU0_SA_DQ<5>")
	)
	(segment
		(start 299.41139 -308.2417)
		(end 298.347638 -308.2417)
		(width 0.18288)
		(layer "In2.Cu")
		(net "M_B_CPU0_SA_DQ<5>")
	)
	(segment
		(start 333.000858 -275.08073)
		(end 333.000858 -275.099272)
		(width 0.088646)
		(layer "In2.Cu")
		(net "M_B_CPU0_SA_DQ<5>")
	)
	(segment
		(start 300.221142 -308.45125)
		(end 299.62094 -308.45125)
		(width 0.18288)
		(layer "In2.Cu")
		(net "M_B_CPU0_SA_DQ<5>")
	)
	(segment
		(start 295.655746 -307.60543)
		(end 295.462706 -307.79847)
		(width 0.18288)
		(layer "In2.Cu")
		(net "M_B_CPU0_SA_DQ<5>")
	)
	(segment
		(start 333.001112 -276.708616)
		(end 333.001112 -276.72284)
		(width 0.088646)
		(layer "In2.Cu")
		(net "M_B_CPU0_SA_DQ<5>")
	)
	(segment
		(start 302.79975 -307.259736)
		(end 302.312832 -307.259736)
		(width 0.18288)
		(layer "In2.Cu")
		(net "M_B_CPU0_SA_DQ<5>")
	)
	(segment
		(start 332.640432 -277.25751)
		(end 332.529942 -277.368)
		(width 0.088646)
		(layer "In2.Cu")
		(net "M_B_CPU0_SA_DQ<5>")
	)
	(segment
		(start 297.47972 -308.859682)
		(end 297.47972 -308.416706)
		(width 0.18288)
		(layer "In2.Cu")
		(net "M_B_CPU0_SA_DQ<5>")
	)
	(segment
		(start 296.285666 -308.030626)
		(end 296.285666 -307.79847)
		(width 0.18288)
		(layer "In2.Cu")
		(net "M_B_CPU0_SA_DQ<5>")
	)
	(segment
		(start 332.529942 -277.368)
		(end 332.529942 -277.52294)
		(width 0.088646)
		(layer "In2.Cu")
		(net "M_B_CPU0_SA_DQ<5>")
	)
	(segment
		(start 333.658464 -273.942556)
		(end 333.649574 -273.947636)
		(width 0.088646)
		(layer "In2.Cu")
		(net "M_B_CPU0_SA_DQ<5>")
	)
	(segment
		(start 298.187618 -308.879494)
		(end 298.027598 -309.039514)
		(width 0.18288)
		(layer "In2.Cu")
		(net "M_B_CPU0_SA_DQ<5>")
	)
	(segment
		(start 319.06337 -304.46472)
		(end 315.294518 -308.233572)
		(width 0.18288)
		(layer "In2.Cu")
		(net "M_B_CPU0_SA_DQ<5>")
	)
	(segment
		(start 329.447906 -281.867864)
		(end 329.123294 -282.651708)
		(width 0.18288)
		(layer "In2.Cu")
		(net "M_B_CPU0_SA_DQ<5>")
	)
	(segment
		(start 337.134962 -273.453098)
		(end 337.44789 -273.453098)
		(width 0.088646)
		(layer "In2.Cu")
		(net "M_B_CPU0_SA_DQ<5>")
	)
	(segment
		(start 301.50308 -308.041548)
		(end 301.190914 -307.729382)
		(width 0.18288)
		(layer "In2.Cu")
		(net "M_B_CPU0_SA_DQ<5>")
	)
	(segment
		(start 320.337942 -301.388272)
		(end 319.06337 -304.46472)
		(width 0.18288)
		(layer "In2.Cu")
		(net "M_B_CPU0_SA_DQ<5>")
	)
	(segment
		(start 332.529942 -277.52294)
		(end 332.530196 -277.648162)
		(width 0.088646)
		(layer "In2.Cu")
		(net "M_B_CPU0_SA_DQ<5>")
	)
	(segment
		(start 295.462706 -307.79847)
		(end 295.462706 -308.473602)
		(width 0.18288)
		(layer "In2.Cu")
		(net "M_B_CPU0_SA_DQ<5>")
	)
	(segment
		(start 335.068164 -273.12874)
		(end 335.05775 -273.134836)
		(width 0.088646)
		(layer "In2.Cu")
		(net "M_B_CPU0_SA_DQ<5>")
	)
	(segment
		(start 332.71841 -275.570442)
		(end 332.70952 -275.575522)
		(width 0.088646)
		(layer "In2.Cu")
		(net "M_B_CPU0_SA_DQ<5>")
	)
	(segment
		(start 309.746904 -309.112412)
		(end 308.044596 -309.112412)
		(width 0.18288)
		(layer "In2.Cu")
		(net "M_B_CPU0_SA_DQ<5>")
	)
	(segment
		(start 332.198726 -277.979632)
		(end 329.447906 -280.730452)
		(width 0.18288)
		(layer "In2.Cu")
		(net "M_B_CPU0_SA_DQ<5>")
	)
	(segment
		(start 310.03875 -308.820566)
		(end 309.746904 -309.112412)
		(width 0.18288)
		(layer "In2.Cu")
		(net "M_B_CPU0_SA_DQ<5>")
	)
	(arc
		(start 334.503014 -273.12874)
		(mid 334.315816 -273.078597)
		(end 334.128618 -273.12874)
		(width 0.088646)
		(layer "In2.Cu")
		(net "M_B_CPU0_SA_DQ<5>")
	)
	(arc
		(start 335.993232 -273.137376)
		(mid 335.716757 -273.204696)
		(end 335.44256 -273.12874)
		(width 0.088646)
		(layer "In2.Cu")
		(net "M_B_CPU0_SA_DQ<5>")
	)
	(arc
		(start 333.000858 -275.099272)
		(mid 332.920696 -275.371461)
		(end 332.71841 -275.570442)
		(width 0.088646)
		(layer "In2.Cu")
		(net "M_B_CPU0_SA_DQ<5>")
	)
	(arc
		(start 335.44256 -273.12874)
		(mid 335.255362 -273.078597)
		(end 335.068164 -273.12874)
		(width 0.088646)
		(layer "In2.Cu")
		(net "M_B_CPU0_SA_DQ<5>")
	)
	(arc
		(start 335.05775 -273.134836)
		(mid 334.779572 -273.204559)
		(end 334.503014 -273.12874)
		(width 0.088646)
		(layer "In2.Cu")
		(net "M_B_CPU0_SA_DQ<5>")
	)
	(arc
		(start 333.941166 -273.453098)
		(mid 333.867175 -273.732664)
		(end 333.66456 -273.939)
		(width 0.088646)
		(layer "In2.Cu")
		(net "M_B_CPU0_SA_DQ<5>")
	)
	(arc
		(start 332.70952 -275.575522)
		(mid 332.530923 -275.8948)
		(end 332.70952 -276.214078)
		(width 0.088646)
		(layer "In2.Cu")
		(net "M_B_CPU0_SA_DQ<5>")
	)
	(arc
		(start 337.32216 -273.12874)
		(mid 337.134962 -273.078597)
		(end 336.947764 -273.12874)
		(width 0.088646)
		(layer "In2.Cu")
		(net "M_B_CPU0_SA_DQ<5>")
	)
	(arc
		(start 332.724506 -276.222714)
		(mid 332.927093 -276.429065)
		(end 333.001112 -276.708616)
		(width 0.088646)
		(layer "In2.Cu")
		(net "M_B_CPU0_SA_DQ<5>")
	)
	(arc
		(start 333.17942 -274.761452)
		(mid 333.048506 -274.897812)
		(end 333.000858 -275.08073)
		(width 0.088646)
		(layer "In2.Cu")
		(net "M_B_CPU0_SA_DQ<5>")
	)
	(arc
		(start 333.001112 -276.72284)
		(mid 332.921893 -276.997525)
		(end 332.71841 -277.198328)
		(width 0.088646)
		(layer "In2.Cu")
		(net "M_B_CPU0_SA_DQ<5>")
	)
	(arc
		(start 336.933032 -273.137376)
		(mid 336.656557 -273.204696)
		(end 336.38236 -273.12874)
		(width 0.088646)
		(layer "In2.Cu")
		(net "M_B_CPU0_SA_DQ<5>")
	)
	(arc
		(start 336.38236 -273.12874)
		(mid 336.195162 -273.078597)
		(end 336.007964 -273.12874)
		(width 0.088646)
		(layer "In2.Cu")
		(net "M_B_CPU0_SA_DQ<5>")
	)
	(arc
		(start 337.50504 -273.395948)
		(mid 337.446921 -273.245707)
		(end 337.33105 -273.13382)
		(width 0.088646)
		(layer "In2.Cu")
		(net "M_B_CPU0_SA_DQ<5>")
	)
	(arc
		(start 332.70952 -277.203408)
		(mid 332.673382 -277.228424)
		(end 332.640432 -277.25751)
		(width 0.088646)
		(layer "In2.Cu")
		(net "M_B_CPU0_SA_DQ<5>")
	)
	(arc
		(start 333.649574 -273.947636)
		(mid 333.51866 -274.083996)
		(end 333.471012 -274.266914)
		(width 0.088646)
		(layer "In2.Cu")
		(net "M_B_CPU0_SA_DQ<5>")
	)
	(arc
		(start 334.119728 -273.13382)
		(mid 333.988814 -273.27018)
		(end 333.941166 -273.453098)
		(width 0.088646)
		(layer "In2.Cu")
		(net "M_B_CPU0_SA_DQ<5>")
	)
	(arc
		(start 333.471012 -274.266914)
		(mid 333.397021 -274.54648)
		(end 333.194406 -274.752816)
		(width 0.088646)
		(layer "In2.Cu")
		(net "M_B_CPU0_SA_DQ<5>")
	)
	(segment
		(start 288.28746 -310.605424)
		(end 287.828736 -310.605424)
		(width 0.20066)
		(layer "F.Cu")
		(net "M_B_CPU0_SA_DQ<4>")
	)
	(segment
		(start 292.005512 -309.941722)
		(end 291.556694 -309.941722)
		(width 0.20066)
		(layer "F.Cu")
		(net "M_B_CPU0_SA_DQ<4>")
	)
	(segment
		(start 288.46018 -310.432704)
		(end 288.28746 -310.605424)
		(width 0.20066)
		(layer "F.Cu")
		(net "M_B_CPU0_SA_DQ<4>")
	)
	(segment
		(start 289.239706 -309.941722)
		(end 289.231578 -309.933594)
		(width 0.101854)
		(layer "F.Cu")
		(net "M_B_CPU0_SA_DQ<4>")
	)
	(segment
		(start 294.904414 -310.366664)
		(end 293.799514 -310.366664)
		(width 0.20066)
		(layer "F.Cu")
		(net "M_B_CPU0_SA_DQ<4>")
	)
	(segment
		(start 293.799514 -310.366664)
		(end 292.430454 -310.366664)
		(width 0.20066)
		(layer "F.Cu")
		(net "M_B_CPU0_SA_DQ<4>")
	)
	(segment
		(start 288.66973 -309.933594)
		(end 288.46018 -310.143144)
		(width 0.20066)
		(layer "F.Cu")
		(net "M_B_CPU0_SA_DQ<4>")
	)
	(segment
		(start 287.589976 -310.366664)
		(end 286.255714 -310.366664)
		(width 0.20066)
		(layer "F.Cu")
		(net "M_B_CPU0_SA_DQ<4>")
	)
	(segment
		(start 288.46018 -310.143144)
		(end 288.46018 -310.432704)
		(width 0.20066)
		(layer "F.Cu")
		(net "M_B_CPU0_SA_DQ<4>")
	)
	(segment
		(start 291.556694 -309.941722)
		(end 289.48761 -309.941722)
		(width 0.1016)
		(layer "F.Cu")
		(net "M_B_CPU0_SA_DQ<4>")
	)
	(segment
		(start 287.828736 -310.605424)
		(end 287.589976 -310.366664)
		(width 0.20066)
		(layer "F.Cu")
		(net "M_B_CPU0_SA_DQ<4>")
	)
	(segment
		(start 336.665316 -274.26666)
		(end 336.665062 -274.266914)
		(width 0.20066)
		(layer "F.Cu")
		(net "M_B_CPU0_SA_DQ<4>")
	)
	(segment
		(start 289.48761 -309.941722)
		(end 289.239706 -309.941722)
		(width 0.101854)
		(layer "F.Cu")
		(net "M_B_CPU0_SA_DQ<4>")
	)
	(segment
		(start 336.665316 -273.730974)
		(end 336.665316 -274.26666)
		(width 0.20066)
		(layer "F.Cu")
		(net "M_B_CPU0_SA_DQ<4>")
	)
	(segment
		(start 292.430454 -310.366664)
		(end 292.005512 -309.941722)
		(width 0.20066)
		(layer "F.Cu")
		(net "M_B_CPU0_SA_DQ<4>")
	)
	(segment
		(start 289.231578 -309.933594)
		(end 288.66973 -309.933594)
		(width 0.20066)
		(layer "F.Cu")
		(net "M_B_CPU0_SA_DQ<4>")
	)
	(segment
		(start 298.147994 -310.17972)
		(end 297.987974 -310.0197)
		(width 0.18288)
		(layer "In2.Cu")
		(net "M_B_CPU0_SA_DQ<4>")
	)
	(segment
		(start 333.470758 -277.511256)
		(end 333.470758 -277.697438)
		(width 0.088646)
		(layer "In2.Cu")
		(net "M_B_CPU0_SA_DQ<4>")
	)
	(segment
		(start 297.399964 -310.17972)
		(end 297.399964 -310.630824)
		(width 0.18288)
		(layer "In2.Cu")
		(net "M_B_CPU0_SA_DQ<4>")
	)
	(segment
		(start 299.651928 -310.789574)
		(end 299.086778 -310.789574)
		(width 0.18288)
		(layer "In2.Cu")
		(net "M_B_CPU0_SA_DQ<4>")
	)
	(segment
		(start 334.12811 -274.756372)
		(end 334.11922 -274.761452)
		(width 0.088646)
		(layer "In2.Cu")
		(net "M_B_CPU0_SA_DQ<4>")
	)
	(segment
		(start 298.308776 -310.791606)
		(end 298.147994 -310.630824)
		(width 0.18288)
		(layer "In2.Cu")
		(net "M_B_CPU0_SA_DQ<4>")
	)
	(segment
		(start 332.693772 -278.474424)
		(end 330.138786 -281.02941)
		(width 0.18288)
		(layer "In2.Cu")
		(net "M_B_CPU0_SA_DQ<4>")
	)
	(segment
		(start 311.49798 -309.799736)
		(end 310.555386 -310.74233)
		(width 0.18288)
		(layer "In2.Cu")
		(net "M_B_CPU0_SA_DQ<4>")
	)
	(segment
		(start 334.130904 -274.754848)
		(end 334.12811 -274.756372)
		(width 0.088646)
		(layer "In2.Cu")
		(net "M_B_CPU0_SA_DQ<4>")
	)
	(segment
		(start 315.075824 -309.89143)
		(end 312.138822 -309.89143)
		(width 0.18288)
		(layer "In2.Cu")
		(net "M_B_CPU0_SA_DQ<4>")
	)
	(segment
		(start 333.65821 -275.570442)
		(end 333.64932 -275.575522)
		(width 0.088646)
		(layer "In2.Cu")
		(net "M_B_CPU0_SA_DQ<4>")
	)
	(segment
		(start 295.383712 -310.366664)
		(end 294.904414 -310.366664)
		(width 0.18288)
		(layer "In2.Cu")
		(net "M_B_CPU0_SA_DQ<4>")
	)
	(segment
		(start 321.31127 -301.703232)
		(end 319.930272 -305.036982)
		(width 0.18288)
		(layer "In2.Cu")
		(net "M_B_CPU0_SA_DQ<4>")
	)
	(segment
		(start 295.520364 -310.230012)
		(end 295.383712 -310.366664)
		(width 0.18288)
		(layer "In2.Cu")
		(net "M_B_CPU0_SA_DQ<4>")
	)
	(segment
		(start 295.657016 -309.47233)
		(end 295.520364 -309.608982)
		(width 0.18288)
		(layer "In2.Cu")
		(net "M_B_CPU0_SA_DQ<4>")
	)
	(segment
		(start 321.87896 -298.849796)
		(end 321.31127 -301.703232)
		(width 0.18288)
		(layer "In2.Cu")
		(net "M_B_CPU0_SA_DQ<4>")
	)
	(segment
		(start 336.86115 -273.947636)
		(end 336.85226 -273.942556)
		(width 0.088646)
		(layer "In2.Cu")
		(net "M_B_CPU0_SA_DQ<4>")
	)
	(segment
		(start 334.134206 -274.752816)
		(end 334.130904 -274.754848)
		(width 0.088646)
		(layer "In2.Cu")
		(net "M_B_CPU0_SA_DQ<4>")
	)
	(segment
		(start 329.350878 -284.75813)
		(end 329.221592 -285.070042)
		(width 0.18288)
		(layer "In2.Cu")
		(net "M_B_CPU0_SA_DQ<4>")
	)
	(segment
		(start 306.825142 -310.966866)
		(end 306.479702 -310.966866)
		(width 0.18288)
		(layer "In2.Cu")
		(net "M_B_CPU0_SA_DQ<4>")
	)
	(segment
		(start 333.470758 -277.697438)
		(end 332.693772 -278.474424)
		(width 0.088646)
		(layer "In2.Cu")
		(net "M_B_CPU0_SA_DQ<4>")
	)
	(segment
		(start 304.426366 -311.00395)
		(end 303.176686 -311.00395)
		(width 0.18288)
		(layer "In2.Cu")
		(net "M_B_CPU0_SA_DQ<4>")
	)
	(segment
		(start 296.265346 -310.649366)
		(end 296.265346 -309.66537)
		(width 0.18288)
		(layer "In2.Cu")
		(net "M_B_CPU0_SA_DQ<4>")
	)
	(segment
		(start 330.138786 -282.855924)
		(end 329.350878 -284.75813)
		(width 0.18288)
		(layer "In2.Cu")
		(net "M_B_CPU0_SA_DQ<4>")
	)
	(segment
		(start 329.221592 -285.070042)
		(end 326.430894 -287.86074)
		(width 0.18288)
		(layer "In2.Cu")
		(net "M_B_CPU0_SA_DQ<4>")
	)
	(segment
		(start 334.598264 -273.942556)
		(end 334.589374 -273.947636)
		(width 0.088646)
		(layer "In2.Cu")
		(net "M_B_CPU0_SA_DQ<4>")
	)
	(segment
		(start 306.479702 -310.966866)
		(end 305.608228 -310.095392)
		(width 0.18288)
		(layer "In2.Cu")
		(net "M_B_CPU0_SA_DQ<4>")
	)
	(segment
		(start 312.047128 -309.799736)
		(end 311.49798 -309.799736)
		(width 0.18288)
		(layer "In2.Cu")
		(net "M_B_CPU0_SA_DQ<4>")
	)
	(segment
		(start 305.608228 -310.095392)
		(end 305.334924 -310.095392)
		(width 0.18288)
		(layer "In2.Cu")
		(net "M_B_CPU0_SA_DQ<4>")
	)
	(segment
		(start 297.987974 -310.0197)
		(end 297.559984 -310.0197)
		(width 0.18288)
		(layer "In2.Cu")
		(net "M_B_CPU0_SA_DQ<4>")
	)
	(segment
		(start 333.940658 -275.08073)
		(end 333.940658 -275.099272)
		(width 0.088646)
		(layer "In2.Cu")
		(net "M_B_CPU0_SA_DQ<4>")
	)
	(segment
		(start 303.176686 -311.00395)
		(end 302.125126 -309.95239)
		(width 0.18288)
		(layer "In2.Cu")
		(net "M_B_CPU0_SA_DQ<4>")
	)
	(segment
		(start 297.559984 -310.0197)
		(end 297.399964 -310.17972)
		(width 0.18288)
		(layer "In2.Cu")
		(net "M_B_CPU0_SA_DQ<4>")
	)
	(segment
		(start 319.930272 -305.036982)
		(end 315.075824 -309.89143)
		(width 0.18288)
		(layer "In2.Cu")
		(net "M_B_CPU0_SA_DQ<4>")
	)
	(segment
		(start 333.65821 -276.219158)
		(end 333.664306 -276.222714)
		(width 0.088646)
		(layer "In2.Cu")
		(net "M_B_CPU0_SA_DQ<4>")
	)
	(segment
		(start 312.138822 -309.89143)
		(end 312.047128 -309.799736)
		(width 0.18288)
		(layer "In2.Cu")
		(net "M_B_CPU0_SA_DQ<4>")
	)
	(segment
		(start 336.97799 -274.266914)
		(end 337.03514 -274.209764)
		(width 0.088646)
		(layer "In2.Cu")
		(net "M_B_CPU0_SA_DQ<4>")
	)
	(segment
		(start 299.086778 -310.789574)
		(end 299.084746 -310.791606)
		(width 0.18288)
		(layer "In2.Cu")
		(net "M_B_CPU0_SA_DQ<4>")
	)
	(segment
		(start 310.555386 -310.74233)
		(end 307.049678 -310.74233)
		(width 0.18288)
		(layer "In2.Cu")
		(net "M_B_CPU0_SA_DQ<4>")
	)
	(segment
		(start 297.399964 -310.630824)
		(end 297.218862 -310.811926)
		(width 0.18288)
		(layer "In2.Cu")
		(net "M_B_CPU0_SA_DQ<4>")
	)
	(segment
		(start 302.125126 -309.95239)
		(end 300.489112 -309.95239)
		(width 0.18288)
		(layer "In2.Cu")
		(net "M_B_CPU0_SA_DQ<4>")
	)
	(segment
		(start 336.665062 -274.266914)
		(end 336.97799 -274.266914)
		(width 0.088646)
		(layer "In2.Cu")
		(net "M_B_CPU0_SA_DQ<4>")
	)
	(segment
		(start 326.430894 -287.86074)
		(end 321.87896 -298.849796)
		(width 0.18288)
		(layer "In2.Cu")
		(net "M_B_CPU0_SA_DQ<4>")
	)
	(segment
		(start 330.138786 -281.02941)
		(end 330.138786 -282.855924)
		(width 0.18288)
		(layer "In2.Cu")
		(net "M_B_CPU0_SA_DQ<4>")
	)
	(segment
		(start 333.940912 -276.708616)
		(end 333.940912 -276.72284)
		(width 0.088646)
		(layer "In2.Cu")
		(net "M_B_CPU0_SA_DQ<4>")
	)
	(segment
		(start 299.084746 -310.791606)
		(end 298.308776 -310.791606)
		(width 0.18288)
		(layer "In2.Cu")
		(net "M_B_CPU0_SA_DQ<4>")
	)
	(segment
		(start 296.265346 -309.66537)
		(end 296.072306 -309.47233)
		(width 0.18288)
		(layer "In2.Cu")
		(net "M_B_CPU0_SA_DQ<4>")
	)
	(segment
		(start 333.65821 -277.198328)
		(end 333.64932 -277.203408)
		(width 0.088646)
		(layer "In2.Cu")
		(net "M_B_CPU0_SA_DQ<4>")
	)
	(segment
		(start 333.64932 -276.214078)
		(end 333.65821 -276.219158)
		(width 0.088646)
		(layer "In2.Cu")
		(net "M_B_CPU0_SA_DQ<4>")
	)
	(segment
		(start 297.218862 -310.811926)
		(end 296.427906 -310.811926)
		(width 0.18288)
		(layer "In2.Cu")
		(net "M_B_CPU0_SA_DQ<4>")
	)
	(segment
		(start 307.049678 -310.74233)
		(end 306.825142 -310.966866)
		(width 0.18288)
		(layer "In2.Cu")
		(net "M_B_CPU0_SA_DQ<4>")
	)
	(segment
		(start 296.427906 -310.811926)
		(end 296.265346 -310.649366)
		(width 0.18288)
		(layer "In2.Cu")
		(net "M_B_CPU0_SA_DQ<4>")
	)
	(segment
		(start 296.072306 -309.47233)
		(end 295.657016 -309.47233)
		(width 0.18288)
		(layer "In2.Cu")
		(net "M_B_CPU0_SA_DQ<4>")
	)
	(segment
		(start 298.147994 -310.630824)
		(end 298.147994 -310.17972)
		(width 0.18288)
		(layer "In2.Cu")
		(net "M_B_CPU0_SA_DQ<4>")
	)
	(segment
		(start 300.489112 -309.95239)
		(end 299.651928 -310.789574)
		(width 0.18288)
		(layer "In2.Cu")
		(net "M_B_CPU0_SA_DQ<4>")
	)
	(segment
		(start 305.334924 -310.095392)
		(end 304.426366 -311.00395)
		(width 0.18288)
		(layer "In2.Cu")
		(net "M_B_CPU0_SA_DQ<4>")
	)
	(segment
		(start 295.520364 -309.608982)
		(end 295.520364 -310.230012)
		(width 0.18288)
		(layer "In2.Cu")
		(net "M_B_CPU0_SA_DQ<4>")
	)
	(arc
		(start 334.589374 -273.947636)
		(mid 334.45846 -274.083996)
		(end 334.410812 -274.266914)
		(width 0.088646)
		(layer "In2.Cu")
		(net "M_B_CPU0_SA_DQ<4>")
	)
	(arc
		(start 335.538064 -273.942556)
		(mid 335.255362 -274.018332)
		(end 334.97266 -273.942556)
		(width 0.088646)
		(layer "In2.Cu")
		(net "M_B_CPU0_SA_DQ<4>")
	)
	(arc
		(start 333.664306 -276.222714)
		(mid 333.866893 -276.429065)
		(end 333.940912 -276.708616)
		(width 0.088646)
		(layer "In2.Cu")
		(net "M_B_CPU0_SA_DQ<4>")
	)
	(arc
		(start 333.940658 -275.099272)
		(mid 333.860496 -275.371461)
		(end 333.65821 -275.570442)
		(width 0.088646)
		(layer "In2.Cu")
		(net "M_B_CPU0_SA_DQ<4>")
	)
	(arc
		(start 334.11922 -274.761452)
		(mid 333.988306 -274.897812)
		(end 333.940658 -275.08073)
		(width 0.088646)
		(layer "In2.Cu")
		(net "M_B_CPU0_SA_DQ<4>")
	)
	(arc
		(start 337.03514 -274.209764)
		(mid 336.977021 -274.059523)
		(end 336.86115 -273.947636)
		(width 0.088646)
		(layer "In2.Cu")
		(net "M_B_CPU0_SA_DQ<4>")
	)
	(arc
		(start 336.85226 -273.942556)
		(mid 336.665062 -273.892413)
		(end 336.477864 -273.942556)
		(width 0.088646)
		(layer "In2.Cu")
		(net "M_B_CPU0_SA_DQ<4>")
	)
	(arc
		(start 335.91246 -273.942556)
		(mid 335.725262 -273.892413)
		(end 335.538064 -273.942556)
		(width 0.088646)
		(layer "In2.Cu")
		(net "M_B_CPU0_SA_DQ<4>")
	)
	(arc
		(start 333.64932 -275.575522)
		(mid 333.470723 -275.8948)
		(end 333.64932 -276.214078)
		(width 0.088646)
		(layer "In2.Cu")
		(net "M_B_CPU0_SA_DQ<4>")
	)
	(arc
		(start 334.410812 -274.266914)
		(mid 334.336821 -274.54648)
		(end 334.134206 -274.752816)
		(width 0.088646)
		(layer "In2.Cu")
		(net "M_B_CPU0_SA_DQ<4>")
	)
	(arc
		(start 333.64932 -277.203408)
		(mid 333.521143 -277.334781)
		(end 333.470758 -277.511256)
		(width 0.088646)
		(layer "In2.Cu")
		(net "M_B_CPU0_SA_DQ<4>")
	)
	(arc
		(start 333.940912 -276.72284)
		(mid 333.861693 -276.997525)
		(end 333.65821 -277.198328)
		(width 0.088646)
		(layer "In2.Cu")
		(net "M_B_CPU0_SA_DQ<4>")
	)
	(arc
		(start 336.477864 -273.942556)
		(mid 336.195162 -274.018332)
		(end 335.91246 -273.942556)
		(width 0.088646)
		(layer "In2.Cu")
		(net "M_B_CPU0_SA_DQ<4>")
	)
	(arc
		(start 334.97266 -273.942556)
		(mid 334.785462 -273.892413)
		(end 334.598264 -273.942556)
		(width 0.088646)
		(layer "In2.Cu")
		(net "M_B_CPU0_SA_DQ<4>")
	)
	(segment
		(start 295.82237 -313.76239)
		(end 295.693846 -313.890914)
		(width 0.20066)
		(layer "F.Cu")
		(net "M_B_CPU0_SA_DQ<3>")
	)
	(segment
		(start 295.693846 -314.042552)
		(end 295.544748 -314.19165)
		(width 0.20066)
		(layer "F.Cu")
		(net "M_B_CPU0_SA_DQ<3>")
	)
	(segment
		(start 292.05301 -313.766708)
		(end 290.355782 -313.766708)
		(width 0.20066)
		(layer "F.Cu")
		(net "M_B_CPU0_SA_DQ<3>")
	)
	(segment
		(start 295.544748 -314.19165)
		(end 295.000426 -314.19165)
		(width 0.20066)
		(layer "F.Cu")
		(net "M_B_CPU0_SA_DQ<3>")
	)
	(segment
		(start 297.08348 -313.766708)
		(end 296.875962 -313.974226)
		(width 0.20066)
		(layer "F.Cu")
		(net "M_B_CPU0_SA_DQ<3>")
	)
	(segment
		(start 296.42943 -313.974226)
		(end 296.217594 -313.76239)
		(width 0.20066)
		(layer "F.Cu")
		(net "M_B_CPU0_SA_DQ<3>")
	)
	(segment
		(start 292.67531 -314.205874)
		(end 292.321488 -314.205874)
		(width 0.20066)
		(layer "F.Cu")
		(net "M_B_CPU0_SA_DQ<3>")
	)
	(segment
		(start 295.000426 -314.19165)
		(end 292.927532 -314.19165)
		(width 0.1016)
		(layer "F.Cu")
		(net "M_B_CPU0_SA_DQ<3>")
	)
	(segment
		(start 292.321488 -314.205874)
		(end 292.178994 -314.06338)
		(width 0.20066)
		(layer "F.Cu")
		(net "M_B_CPU0_SA_DQ<3>")
	)
	(segment
		(start 292.178994 -313.892692)
		(end 292.05301 -313.766708)
		(width 0.20066)
		(layer "F.Cu")
		(net "M_B_CPU0_SA_DQ<3>")
	)
	(segment
		(start 296.875962 -313.974226)
		(end 296.42943 -313.974226)
		(width 0.20066)
		(layer "F.Cu")
		(net "M_B_CPU0_SA_DQ<3>")
	)
	(segment
		(start 296.217594 -313.76239)
		(end 295.82237 -313.76239)
		(width 0.20066)
		(layer "F.Cu")
		(net "M_B_CPU0_SA_DQ<3>")
	)
	(segment
		(start 338.544916 -275.35886)
		(end 338.544916 -275.894292)
		(width 0.20066)
		(layer "F.Cu")
		(net "M_B_CPU0_SA_DQ<3>")
	)
	(segment
		(start 292.689534 -314.19165)
		(end 292.67531 -314.205874)
		(width 0.101854)
		(layer "F.Cu")
		(net "M_B_CPU0_SA_DQ<3>")
	)
	(segment
		(start 297.899582 -313.766708)
		(end 297.08348 -313.766708)
		(width 0.20066)
		(layer "F.Cu")
		(net "M_B_CPU0_SA_DQ<3>")
	)
	(segment
		(start 295.693846 -313.890914)
		(end 295.693846 -314.042552)
		(width 0.20066)
		(layer "F.Cu")
		(net "M_B_CPU0_SA_DQ<3>")
	)
	(segment
		(start 292.178994 -314.06338)
		(end 292.178994 -313.892692)
		(width 0.20066)
		(layer "F.Cu")
		(net "M_B_CPU0_SA_DQ<3>")
	)
	(segment
		(start 299.029882 -313.766708)
		(end 297.899582 -313.766708)
		(width 0.20066)
		(layer "F.Cu")
		(net "M_B_CPU0_SA_DQ<3>")
	)
	(segment
		(start 292.927532 -314.19165)
		(end 292.689534 -314.19165)
		(width 0.101854)
		(layer "F.Cu")
		(net "M_B_CPU0_SA_DQ<3>")
	)
	(arc
		(start 338.544916 -275.894292)
		(mid 338.544858 -275.894584)
		(end 338.544662 -275.8948)
		(width 0.20066)
		(layer "F.Cu")
		(net "M_B_CPU0_SA_DQ<3>")
	)
	(segment
		(start 303.171606 -314.360306)
		(end 302.978566 -314.553346)
		(width 0.18288)
		(layer "In2.Cu")
		(net "M_B_CPU0_SA_DQ<3>")
	)
	(segment
		(start 311.060084 -313.81954)
		(end 310.787288 -313.81954)
		(width 0.18288)
		(layer "In2.Cu")
		(net "M_B_CPU0_SA_DQ<3>")
	)
	(segment
		(start 337.820762 -275.586952)
		(end 337.79206 -275.570188)
		(width 0.088646)
		(layer "In2.Cu")
		(net "M_B_CPU0_SA_DQ<3>")
	)
	(segment
		(start 304.61712 -315.08827)
		(end 304.45837 -315.24702)
		(width 0.18288)
		(layer "In2.Cu")
		(net "M_B_CPU0_SA_DQ<3>")
	)
	(segment
		(start 310.50865 -315.293248)
		(end 310.14416 -314.928758)
		(width 0.18288)
		(layer "In2.Cu")
		(net "M_B_CPU0_SA_DQ<3>")
	)
	(segment
		(start 328.548492 -288.82467)
		(end 323.80047 -300.287182)
		(width 0.18288)
		(layer "In2.Cu")
		(net "M_B_CPU0_SA_DQ<3>")
	)
	(segment
		(start 336.852006 -277.847044)
		(end 336.843878 -277.85187)
		(width 0.088646)
		(layer "In2.Cu")
		(net "M_B_CPU0_SA_DQ<3>")
	)
	(segment
		(start 312.734452 -314.533534)
		(end 312.374026 -314.173108)
		(width 0.18288)
		(layer "In2.Cu")
		(net "M_B_CPU0_SA_DQ<3>")
	)
	(segment
		(start 299.787564 -314.136278)
		(end 299.417994 -313.766708)
		(width 0.18288)
		(layer "In2.Cu")
		(net "M_B_CPU0_SA_DQ<3>")
	)
	(segment
		(start 311.001156 -315.073538)
		(end 310.781446 -315.293248)
		(width 0.18288)
		(layer "In2.Cu")
		(net "M_B_CPU0_SA_DQ<3>")
	)
	(segment
		(start 323.1769 -303.422304)
		(end 321.987672 -306.293012)
		(width 0.18288)
		(layer "In2.Cu")
		(net "M_B_CPU0_SA_DQ<3>")
	)
	(segment
		(start 311.001156 -314.790836)
		(end 311.001156 -315.073538)
		(width 0.18288)
		(layer "In2.Cu")
		(net "M_B_CPU0_SA_DQ<3>")
	)
	(segment
		(start 303.682146 -314.553346)
		(end 303.489106 -314.360306)
		(width 0.18288)
		(layer "In2.Cu")
		(net "M_B_CPU0_SA_DQ<3>")
	)
	(segment
		(start 334.220312 -280.759662)
		(end 334.220312 -280.778204)
		(width 0.088646)
		(layer "In2.Cu")
		(net "M_B_CPU0_SA_DQ<3>")
	)
	(segment
		(start 312.374026 -314.173108)
		(end 311.413652 -314.173108)
		(width 0.18288)
		(layer "In2.Cu")
		(net "M_B_CPU0_SA_DQ<3>")
	)
	(segment
		(start 310.544972 -314.061856)
		(end 310.544972 -314.334652)
		(width 0.18288)
		(layer "In2.Cu")
		(net "M_B_CPU0_SA_DQ<3>")
	)
	(segment
		(start 331.815186 -284.488128)
		(end 331.65034 -284.886146)
		(width 0.18288)
		(layer "In2.Cu")
		(net "M_B_CPU0_SA_DQ<3>")
	)
	(segment
		(start 335.630012 -279.954228)
		(end 335.630012 -279.964134)
		(width 0.088646)
		(layer "In2.Cu")
		(net "M_B_CPU0_SA_DQ<3>")
	)
	(segment
		(start 336.860896 -277.841964)
		(end 336.852006 -277.847044)
		(width 0.088646)
		(layer "In2.Cu")
		(net "M_B_CPU0_SA_DQ<3>")
	)
	(segment
		(start 309.871364 -314.928758)
		(end 309.433214 -315.366908)
		(width 0.18288)
		(layer "In2.Cu")
		(net "M_B_CPU0_SA_DQ<3>")
	)
	(segment
		(start 310.14416 -314.928758)
		(end 309.871364 -314.928758)
		(width 0.18288)
		(layer "In2.Cu")
		(net "M_B_CPU0_SA_DQ<3>")
	)
	(segment
		(start 308.494938 -315.366908)
		(end 308.11343 -314.9854)
		(width 0.18288)
		(layer "In2.Cu")
		(net "M_B_CPU0_SA_DQ<3>")
	)
	(segment
		(start 309.433214 -315.366908)
		(end 308.494938 -315.366908)
		(width 0.18288)
		(layer "In2.Cu")
		(net "M_B_CPU0_SA_DQ<3>")
	)
	(segment
		(start 336.099912 -279.140412)
		(end 336.099912 -279.150318)
		(width 0.088646)
		(layer "In2.Cu")
		(net "M_B_CPU0_SA_DQ<3>")
	)
	(segment
		(start 303.909984 -315.24702)
		(end 303.682146 -315.019182)
		(width 0.18288)
		(layer "In2.Cu")
		(net "M_B_CPU0_SA_DQ<3>")
	)
	(segment
		(start 323.80047 -300.287182)
		(end 323.1769 -303.422304)
		(width 0.18288)
		(layer "In2.Cu")
		(net "M_B_CPU0_SA_DQ<3>")
	)
	(segment
		(start 336.477864 -275.570442)
		(end 336.477864 -275.570696)
		(width 0.088646)
		(layer "In2.Cu")
		(net "M_B_CPU0_SA_DQ<3>")
	)
	(segment
		(start 302.978566 -314.903358)
		(end 302.861726 -315.020198)
		(width 0.18288)
		(layer "In2.Cu")
		(net "M_B_CPU0_SA_DQ<3>")
	)
	(segment
		(start 333.28991 -281.141678)
		(end 332.922118 -281.141678)
		(width 0.18288)
		(layer "In2.Cu")
		(net "M_B_CPU0_SA_DQ<3>")
	)
	(segment
		(start 336.568288 -278.336756)
		(end 336.568288 -278.34463)
		(width 0.088646)
		(layer "In2.Cu")
		(net "M_B_CPU0_SA_DQ<3>")
	)
	(segment
		(start 331.815186 -282.24861)
		(end 331.815186 -284.488128)
		(width 0.18288)
		(layer "In2.Cu")
		(net "M_B_CPU0_SA_DQ<3>")
	)
	(segment
		(start 333.88554 -281.141678)
		(end 333.28991 -281.141678)
		(width 0.088646)
		(layer "In2.Cu")
		(net "M_B_CPU0_SA_DQ<3>")
	)
	(segment
		(start 308.11343 -314.9854)
		(end 307.500782 -314.9854)
		(width 0.18288)
		(layer "In2.Cu")
		(net "M_B_CPU0_SA_DQ<3>")
	)
	(segment
		(start 336.569812 -276.54377)
		(end 336.569812 -276.730714)
		(width 0.088646)
		(layer "In2.Cu")
		(net "M_B_CPU0_SA_DQ<3>")
	)
	(segment
		(start 302.125888 -314.23991)
		(end 300.038008 -314.23991)
		(width 0.18288)
		(layer "In2.Cu")
		(net "M_B_CPU0_SA_DQ<3>")
	)
	(segment
		(start 321.987672 -306.293012)
		(end 315.663326 -312.617358)
		(width 0.18288)
		(layer "In2.Cu")
		(net "M_B_CPU0_SA_DQ<3>")
	)
	(segment
		(start 336.56905 -278.336756)
		(end 336.568288 -278.336756)
		(width 0.088646)
		(layer "In2.Cu")
		(net "M_B_CPU0_SA_DQ<3>")
	)
	(segment
		(start 313.077606 -314.533534)
		(end 312.734452 -314.533534)
		(width 0.18288)
		(layer "In2.Cu")
		(net "M_B_CPU0_SA_DQ<3>")
	)
	(segment
		(start 338.544662 -275.8948)
		(end 337.820762 -275.586952)
		(width 0.088646)
		(layer "In2.Cu")
		(net "M_B_CPU0_SA_DQ<3>")
	)
	(segment
		(start 306.327302 -315.08827)
		(end 304.61712 -315.08827)
		(width 0.18288)
		(layer "In2.Cu")
		(net "M_B_CPU0_SA_DQ<3>")
	)
	(segment
		(start 336.852006 -277.198328)
		(end 336.860896 -277.203408)
		(width 0.088646)
		(layer "In2.Cu")
		(net "M_B_CPU0_SA_DQ<3>")
	)
	(segment
		(start 314.779406 -313.106816)
		(end 314.779406 -313.501278)
		(width 0.18288)
		(layer "In2.Cu")
		(net "M_B_CPU0_SA_DQ<3>")
	)
	(segment
		(start 307.189632 -315.29655)
		(end 306.535582 -315.29655)
		(width 0.18288)
		(layer "In2.Cu")
		(net "M_B_CPU0_SA_DQ<3>")
	)
	(segment
		(start 314.107576 -314.173108)
		(end 313.438032 -314.173108)
		(width 0.18288)
		(layer "In2.Cu")
		(net "M_B_CPU0_SA_DQ<3>")
	)
	(segment
		(start 304.45837 -315.24702)
		(end 303.909984 -315.24702)
		(width 0.18288)
		(layer "In2.Cu")
		(net "M_B_CPU0_SA_DQ<3>")
	)
	(segment
		(start 335.92135 -279.469596)
		(end 335.91246 -279.474676)
		(width 0.088646)
		(layer "In2.Cu")
		(net "M_B_CPU0_SA_DQ<3>")
	)
	(segment
		(start 303.489106 -314.360306)
		(end 303.171606 -314.360306)
		(width 0.18288)
		(layer "In2.Cu")
		(net "M_B_CPU0_SA_DQ<3>")
	)
	(segment
		(start 331.059028 -286.314134)
		(end 328.548492 -288.82467)
		(width 0.18288)
		(layer "In2.Cu")
		(net "M_B_CPU0_SA_DQ<3>")
	)
	(segment
		(start 310.544972 -314.334652)
		(end 311.001156 -314.790836)
		(width 0.18288)
		(layer "In2.Cu")
		(net "M_B_CPU0_SA_DQ<3>")
	)
	(segment
		(start 315.663326 -312.617358)
		(end 315.268864 -312.617358)
		(width 0.18288)
		(layer "In2.Cu")
		(net "M_B_CPU0_SA_DQ<3>")
	)
	(segment
		(start 313.438032 -314.173108)
		(end 313.077606 -314.533534)
		(width 0.18288)
		(layer "In2.Cu")
		(net "M_B_CPU0_SA_DQ<3>")
	)
	(segment
		(start 302.436276 -315.020198)
		(end 302.26635 -314.850272)
		(width 0.18288)
		(layer "In2.Cu")
		(net "M_B_CPU0_SA_DQ<3>")
	)
	(segment
		(start 307.500782 -314.9854)
		(end 307.189632 -315.29655)
		(width 0.18288)
		(layer "In2.Cu")
		(net "M_B_CPU0_SA_DQ<3>")
	)
	(segment
		(start 336.290412 -275.8948)
		(end 336.290412 -276.065488)
		(width 0.088646)
		(layer "In2.Cu")
		(net "M_B_CPU0_SA_DQ<3>")
	)
	(segment
		(start 314.779406 -313.501278)
		(end 314.107576 -314.173108)
		(width 0.18288)
		(layer "In2.Cu")
		(net "M_B_CPU0_SA_DQ<3>")
	)
	(segment
		(start 311.413652 -314.173108)
		(end 311.060084 -313.81954)
		(width 0.18288)
		(layer "In2.Cu")
		(net "M_B_CPU0_SA_DQ<3>")
	)
	(segment
		(start 331.65034 -284.886146)
		(end 331.059028 -286.314134)
		(width 0.18288)
		(layer "In2.Cu")
		(net "M_B_CPU0_SA_DQ<3>")
	)
	(segment
		(start 335.45145 -280.283412)
		(end 335.44256 -280.288492)
		(width 0.088646)
		(layer "In2.Cu")
		(net "M_B_CPU0_SA_DQ<3>")
	)
	(segment
		(start 300.038008 -314.23991)
		(end 299.787564 -314.136278)
		(width 0.18288)
		(layer "In2.Cu")
		(net "M_B_CPU0_SA_DQ<3>")
	)
	(segment
		(start 336.38744 -278.65705)
		(end 336.39125 -278.65578)
		(width 0.088646)
		(layer "In2.Cu")
		(net "M_B_CPU0_SA_DQ<3>")
	)
	(segment
		(start 310.781446 -315.293248)
		(end 310.50865 -315.293248)
		(width 0.18288)
		(layer "In2.Cu")
		(net "M_B_CPU0_SA_DQ<3>")
	)
	(segment
		(start 306.535582 -315.29655)
		(end 306.327302 -315.08827)
		(width 0.18288)
		(layer "In2.Cu")
		(net "M_B_CPU0_SA_DQ<3>")
	)
	(segment
		(start 336.290412 -276.065488)
		(end 336.430112 -276.301708)
		(width 0.088646)
		(layer "In2.Cu")
		(net "M_B_CPU0_SA_DQ<3>")
	)
	(segment
		(start 332.922118 -281.141678)
		(end 331.815186 -282.24861)
		(width 0.18288)
		(layer "In2.Cu")
		(net "M_B_CPU0_SA_DQ<3>")
	)
	(segment
		(start 337.418172 -275.570188)
		(end 337.417664 -275.570442)
		(width 0.088646)
		(layer "In2.Cu")
		(net "M_B_CPU0_SA_DQ<3>")
	)
	(segment
		(start 302.26635 -314.850272)
		(end 302.26635 -314.380372)
		(width 0.18288)
		(layer "In2.Cu")
		(net "M_B_CPU0_SA_DQ<3>")
	)
	(segment
		(start 303.682146 -315.019182)
		(end 303.682146 -314.553346)
		(width 0.18288)
		(layer "In2.Cu")
		(net "M_B_CPU0_SA_DQ<3>")
	)
	(segment
		(start 310.787288 -313.81954)
		(end 310.544972 -314.061856)
		(width 0.18288)
		(layer "In2.Cu")
		(net "M_B_CPU0_SA_DQ<3>")
	)
	(segment
		(start 302.861726 -315.020198)
		(end 302.436276 -315.020198)
		(width 0.18288)
		(layer "In2.Cu")
		(net "M_B_CPU0_SA_DQ<3>")
	)
	(segment
		(start 302.978566 -314.553346)
		(end 302.978566 -314.903358)
		(width 0.18288)
		(layer "In2.Cu")
		(net "M_B_CPU0_SA_DQ<3>")
	)
	(segment
		(start 336.39125 -278.65578)
		(end 336.38236 -278.66086)
		(width 0.088646)
		(layer "In2.Cu")
		(net "M_B_CPU0_SA_DQ<3>")
	)
	(segment
		(start 299.417994 -313.766708)
		(end 299.029882 -313.766708)
		(width 0.18288)
		(layer "In2.Cu")
		(net "M_B_CPU0_SA_DQ<3>")
	)
	(segment
		(start 302.26635 -314.380372)
		(end 302.125888 -314.23991)
		(width 0.18288)
		(layer "In2.Cu")
		(net "M_B_CPU0_SA_DQ<3>")
	)
	(segment
		(start 315.268864 -312.617358)
		(end 314.779406 -313.106816)
		(width 0.18288)
		(layer "In2.Cu")
		(net "M_B_CPU0_SA_DQ<3>")
	)
	(arc
		(start 335.44256 -280.288492)
		(mid 335.255362 -280.338635)
		(end 335.068164 -280.288492)
		(width 0.088646)
		(layer "In2.Cu")
		(net "M_B_CPU0_SA_DQ<3>")
	)
	(arc
		(start 335.630012 -279.964134)
		(mid 335.582333 -280.147034)
		(end 335.45145 -280.283412)
		(width 0.088646)
		(layer "In2.Cu")
		(net "M_B_CPU0_SA_DQ<3>")
	)
	(arc
		(start 335.91246 -279.474676)
		(mid 335.708125 -279.677281)
		(end 335.630012 -279.954228)
		(width 0.088646)
		(layer "In2.Cu")
		(net "M_B_CPU0_SA_DQ<3>")
	)
	(arc
		(start 334.50276 -280.288492)
		(mid 334.300474 -280.487473)
		(end 334.220312 -280.759662)
		(width 0.088646)
		(layer "In2.Cu")
		(net "M_B_CPU0_SA_DQ<3>")
	)
	(arc
		(start 335.068164 -280.288492)
		(mid 334.785462 -280.21275)
		(end 334.50276 -280.288492)
		(width 0.088646)
		(layer "In2.Cu")
		(net "M_B_CPU0_SA_DQ<3>")
	)
	(arc
		(start 337.79206 -275.570188)
		(mid 337.605116 -275.520104)
		(end 337.418172 -275.570188)
		(width 0.088646)
		(layer "In2.Cu")
		(net "M_B_CPU0_SA_DQ<3>")
	)
	(arc
		(start 336.860896 -277.203408)
		(mid 337.039493 -277.522686)
		(end 336.860896 -277.841964)
		(width 0.088646)
		(layer "In2.Cu")
		(net "M_B_CPU0_SA_DQ<3>")
	)
	(arc
		(start 336.568288 -278.34463)
		(mid 336.518057 -278.524107)
		(end 336.38744 -278.65705)
		(width 0.088646)
		(layer "In2.Cu")
		(net "M_B_CPU0_SA_DQ<3>")
	)
	(arc
		(start 337.417664 -275.570442)
		(mid 337.134962 -275.646184)
		(end 336.85226 -275.570442)
		(width 0.088646)
		(layer "In2.Cu")
		(net "M_B_CPU0_SA_DQ<3>")
	)
	(arc
		(start 336.430112 -276.301708)
		(mid 336.53235 -276.40404)
		(end 336.569812 -276.54377)
		(width 0.088646)
		(layer "In2.Cu")
		(net "M_B_CPU0_SA_DQ<3>")
	)
	(arc
		(start 336.843878 -277.85187)
		(mid 336.64253 -278.058077)
		(end 336.56905 -278.336756)
		(width 0.088646)
		(layer "In2.Cu")
		(net "M_B_CPU0_SA_DQ<3>")
	)
	(arc
		(start 334.04175 -281.097482)
		(mid 333.96672 -281.130468)
		(end 333.88554 -281.141678)
		(width 0.088646)
		(layer "In2.Cu")
		(net "M_B_CPU0_SA_DQ<3>")
	)
	(arc
		(start 334.220312 -280.778204)
		(mid 334.172633 -280.961104)
		(end 334.04175 -281.097482)
		(width 0.088646)
		(layer "In2.Cu")
		(net "M_B_CPU0_SA_DQ<3>")
	)
	(arc
		(start 336.569812 -276.730714)
		(mid 336.650723 -277.000842)
		(end 336.852006 -277.198328)
		(width 0.088646)
		(layer "In2.Cu")
		(net "M_B_CPU0_SA_DQ<3>")
	)
	(arc
		(start 336.099912 -279.150318)
		(mid 336.052233 -279.333218)
		(end 335.92135 -279.469596)
		(width 0.088646)
		(layer "In2.Cu")
		(net "M_B_CPU0_SA_DQ<3>")
	)
	(arc
		(start 336.38236 -278.66086)
		(mid 336.178025 -278.863465)
		(end 336.099912 -279.140412)
		(width 0.088646)
		(layer "In2.Cu")
		(net "M_B_CPU0_SA_DQ<3>")
	)
	(arc
		(start 336.477864 -275.570696)
		(mid 336.340641 -275.707593)
		(end 336.290412 -275.8948)
		(width 0.088646)
		(layer "In2.Cu")
		(net "M_B_CPU0_SA_DQ<3>")
	)
	(arc
		(start 336.85226 -275.570442)
		(mid 336.665062 -275.520299)
		(end 336.477864 -275.570442)
		(width 0.088646)
		(layer "In2.Cu")
		(net "M_B_CPU0_SA_DQ<3>")
	)
	(segment
		(start 296.875962 -279.974294)
		(end 296.42943 -279.974294)
		(width 0.20066)
		(layer "F.Cu")
		(net "M_B_CPU0_SA_DQ<31>")
	)
	(segment
		(start 292.178994 -280.063448)
		(end 292.178994 -279.89276)
		(width 0.20066)
		(layer "F.Cu")
		(net "M_B_CPU0_SA_DQ<31>")
	)
	(segment
		(start 299.029882 -279.766776)
		(end 297.899582 -279.766776)
		(width 0.20066)
		(layer "F.Cu")
		(net "M_B_CPU0_SA_DQ<31>")
	)
	(segment
		(start 341.364316 -260.708902)
		(end 341.364316 -261.244588)
		(width 0.20066)
		(layer "F.Cu")
		(net "M_B_CPU0_SA_DQ<31>")
	)
	(segment
		(start 295.544748 -280.191718)
		(end 295.000426 -280.191718)
		(width 0.20066)
		(layer "F.Cu")
		(net "M_B_CPU0_SA_DQ<31>")
	)
	(segment
		(start 292.321488 -280.205942)
		(end 292.178994 -280.063448)
		(width 0.20066)
		(layer "F.Cu")
		(net "M_B_CPU0_SA_DQ<31>")
	)
	(segment
		(start 297.08348 -279.766776)
		(end 296.875962 -279.974294)
		(width 0.20066)
		(layer "F.Cu")
		(net "M_B_CPU0_SA_DQ<31>")
	)
	(segment
		(start 295.82237 -279.762458)
		(end 295.693846 -279.890982)
		(width 0.20066)
		(layer "F.Cu")
		(net "M_B_CPU0_SA_DQ<31>")
	)
	(segment
		(start 295.693846 -279.890982)
		(end 295.693846 -280.04262)
		(width 0.20066)
		(layer "F.Cu")
		(net "M_B_CPU0_SA_DQ<31>")
	)
	(segment
		(start 292.689534 -280.191718)
		(end 292.67531 -280.205942)
		(width 0.101854)
		(layer "F.Cu")
		(net "M_B_CPU0_SA_DQ<31>")
	)
	(segment
		(start 292.178994 -279.89276)
		(end 292.05301 -279.766776)
		(width 0.20066)
		(layer "F.Cu")
		(net "M_B_CPU0_SA_DQ<31>")
	)
	(segment
		(start 292.67531 -280.205942)
		(end 292.321488 -280.205942)
		(width 0.20066)
		(layer "F.Cu")
		(net "M_B_CPU0_SA_DQ<31>")
	)
	(segment
		(start 295.000426 -280.191718)
		(end 292.927532 -280.191718)
		(width 0.1016)
		(layer "F.Cu")
		(net "M_B_CPU0_SA_DQ<31>")
	)
	(segment
		(start 341.364316 -261.244588)
		(end 341.364062 -261.244842)
		(width 0.20066)
		(layer "F.Cu")
		(net "M_B_CPU0_SA_DQ<31>")
	)
	(segment
		(start 296.42943 -279.974294)
		(end 296.217594 -279.762458)
		(width 0.20066)
		(layer "F.Cu")
		(net "M_B_CPU0_SA_DQ<31>")
	)
	(segment
		(start 297.899582 -279.766776)
		(end 297.08348 -279.766776)
		(width 0.20066)
		(layer "F.Cu")
		(net "M_B_CPU0_SA_DQ<31>")
	)
	(segment
		(start 296.217594 -279.762458)
		(end 295.82237 -279.762458)
		(width 0.20066)
		(layer "F.Cu")
		(net "M_B_CPU0_SA_DQ<31>")
	)
	(segment
		(start 292.05301 -279.766776)
		(end 290.355782 -279.766776)
		(width 0.20066)
		(layer "F.Cu")
		(net "M_B_CPU0_SA_DQ<31>")
	)
	(segment
		(start 292.927532 -280.191718)
		(end 292.689534 -280.191718)
		(width 0.101854)
		(layer "F.Cu")
		(net "M_B_CPU0_SA_DQ<31>")
	)
	(segment
		(start 295.693846 -280.04262)
		(end 295.544748 -280.191718)
		(width 0.20066)
		(layer "F.Cu")
		(net "M_B_CPU0_SA_DQ<31>")
	)
	(segment
		(start 300.796198 -276.443694)
		(end 300.796198 -278.791162)
		(width 0.18288)
		(layer "In4.Cu")
		(net "M_B_CPU0_SA_DQ<31>")
	)
	(segment
		(start 299.56379 -279.232868)
		(end 299.029882 -279.766776)
		(width 0.18288)
		(layer "In4.Cu")
		(net "M_B_CPU0_SA_DQ<31>")
	)
	(segment
		(start 304.682144 -274.165568)
		(end 304.966116 -274.44954)
		(width 0.18288)
		(layer "In4.Cu")
		(net "M_B_CPU0_SA_DQ<31>")
	)
	(segment
		(start 312.15711 -270.032226)
		(end 310.92394 -271.265396)
		(width 0.18288)
		(layer "In4.Cu")
		(net "M_B_CPU0_SA_DQ<31>")
	)
	(segment
		(start 304.47742 -274.938236)
		(end 304.193448 -274.654264)
		(width 0.18288)
		(layer "In4.Cu")
		(net "M_B_CPU0_SA_DQ<31>")
	)
	(segment
		(start 303.043336 -275.545804)
		(end 301.694088 -275.545804)
		(width 0.18288)
		(layer "In4.Cu")
		(net "M_B_CPU0_SA_DQ<31>")
	)
	(segment
		(start 313.866022 -270.032226)
		(end 312.15711 -270.032226)
		(width 0.18288)
		(layer "In4.Cu")
		(net "M_B_CPU0_SA_DQ<31>")
	)
	(segment
		(start 308.644798 -272.100294)
		(end 308.644798 -271.425416)
		(width 0.18288)
		(layer "In4.Cu")
		(net "M_B_CPU0_SA_DQ<31>")
	)
	(segment
		(start 341.364062 -261.244842)
		(end 341.051388 -261.244842)
		(width 0.088646)
		(layer "In4.Cu")
		(net "M_B_CPU0_SA_DQ<31>")
	)
	(segment
		(start 305.943508 -273.472148)
		(end 305.943508 -273.73072)
		(width 0.18288)
		(layer "In4.Cu")
		(net "M_B_CPU0_SA_DQ<31>")
	)
	(segment
		(start 309.338218 -272.100294)
		(end 309.178198 -272.260314)
		(width 0.18288)
		(layer "In4.Cu")
		(net "M_B_CPU0_SA_DQ<31>")
	)
	(segment
		(start 313.866276 -270.031972)
		(end 313.866022 -270.032226)
		(width 0.18288)
		(layer "In4.Cu")
		(net "M_B_CPU0_SA_DQ<31>")
	)
	(segment
		(start 331.323442 -260.711188)
		(end 331.081634 -260.46938)
		(width 0.088646)
		(layer "In4.Cu")
		(net "M_B_CPU0_SA_DQ<31>")
	)
	(segment
		(start 304.193448 -274.654264)
		(end 303.934876 -274.654264)
		(width 0.18288)
		(layer "In4.Cu")
		(net "M_B_CPU0_SA_DQ<31>")
	)
	(segment
		(start 326.931274 -260.46938)
		(end 323.19214 -262.018526)
		(width 0.18288)
		(layer "In4.Cu")
		(net "M_B_CPU0_SA_DQ<31>")
	)
	(segment
		(start 307.323744 -271.265396)
		(end 305.659536 -272.929604)
		(width 0.18288)
		(layer "In4.Cu")
		(net "M_B_CPU0_SA_DQ<31>")
	)
	(segment
		(start 304.912268 -273.676872)
		(end 304.682144 -273.906996)
		(width 0.18288)
		(layer "In4.Cu")
		(net "M_B_CPU0_SA_DQ<31>")
	)
	(segment
		(start 330.724002 -260.46938)
		(end 326.931274 -260.46938)
		(width 0.18288)
		(layer "In4.Cu")
		(net "M_B_CPU0_SA_DQ<31>")
	)
	(segment
		(start 305.659536 -272.929604)
		(end 305.659536 -273.188176)
		(width 0.18288)
		(layer "In4.Cu")
		(net "M_B_CPU0_SA_DQ<31>")
	)
	(segment
		(start 341.051388 -261.244842)
		(end 340.98611 -261.179564)
		(width 0.088646)
		(layer "In4.Cu")
		(net "M_B_CPU0_SA_DQ<31>")
	)
	(segment
		(start 338.272374 -260.749034)
		(end 338.26196 -260.75513)
		(width 0.088646)
		(layer "In4.Cu")
		(net "M_B_CPU0_SA_DQ<31>")
	)
	(segment
		(start 304.682144 -273.906996)
		(end 304.682144 -274.165568)
		(width 0.18288)
		(layer "In4.Cu")
		(net "M_B_CPU0_SA_DQ<31>")
	)
	(segment
		(start 300.796198 -278.791162)
		(end 300.354492 -279.232868)
		(width 0.18288)
		(layer "In4.Cu")
		(net "M_B_CPU0_SA_DQ<31>")
	)
	(segment
		(start 336.392774 -260.749034)
		(end 336.38236 -260.75513)
		(width 0.088646)
		(layer "In4.Cu")
		(net "M_B_CPU0_SA_DQ<31>")
	)
	(segment
		(start 309.178198 -272.260314)
		(end 308.804818 -272.260314)
		(width 0.18288)
		(layer "In4.Cu")
		(net "M_B_CPU0_SA_DQ<31>")
	)
	(segment
		(start 331.081634 -260.46938)
		(end 330.724002 -260.46938)
		(width 0.088646)
		(layer "In4.Cu")
		(net "M_B_CPU0_SA_DQ<31>")
	)
	(segment
		(start 304.735992 -274.938236)
		(end 304.47742 -274.938236)
		(width 0.18288)
		(layer "In4.Cu")
		(net "M_B_CPU0_SA_DQ<31>")
	)
	(segment
		(start 308.804818 -272.260314)
		(end 308.644798 -272.100294)
		(width 0.18288)
		(layer "In4.Cu")
		(net "M_B_CPU0_SA_DQ<31>")
	)
	(segment
		(start 339.212428 -260.749034)
		(end 339.202014 -260.75513)
		(width 0.088646)
		(layer "In4.Cu")
		(net "M_B_CPU0_SA_DQ<31>")
	)
	(segment
		(start 310.92394 -271.265396)
		(end 309.498238 -271.265396)
		(width 0.18288)
		(layer "In4.Cu")
		(net "M_B_CPU0_SA_DQ<31>")
	)
	(segment
		(start 304.966116 -274.44954)
		(end 304.966116 -274.708112)
		(width 0.18288)
		(layer "In4.Cu")
		(net "M_B_CPU0_SA_DQ<31>")
	)
	(segment
		(start 305.17084 -273.676872)
		(end 304.912268 -273.676872)
		(width 0.18288)
		(layer "In4.Cu")
		(net "M_B_CPU0_SA_DQ<31>")
	)
	(segment
		(start 304.966116 -274.708112)
		(end 304.735992 -274.938236)
		(width 0.18288)
		(layer "In4.Cu")
		(net "M_B_CPU0_SA_DQ<31>")
	)
	(segment
		(start 308.484778 -271.265396)
		(end 307.323744 -271.265396)
		(width 0.18288)
		(layer "In4.Cu")
		(net "M_B_CPU0_SA_DQ<31>")
	)
	(segment
		(start 308.644798 -271.425416)
		(end 308.484778 -271.265396)
		(width 0.18288)
		(layer "In4.Cu")
		(net "M_B_CPU0_SA_DQ<31>")
	)
	(segment
		(start 305.713384 -273.960844)
		(end 305.454812 -273.960844)
		(width 0.18288)
		(layer "In4.Cu")
		(net "M_B_CPU0_SA_DQ<31>")
	)
	(segment
		(start 331.68336 -260.75513)
		(end 331.678534 -260.757924)
		(width 0.088646)
		(layer "In4.Cu")
		(net "M_B_CPU0_SA_DQ<31>")
	)
	(segment
		(start 303.934876 -274.654264)
		(end 303.043336 -275.545804)
		(width 0.18288)
		(layer "In4.Cu")
		(net "M_B_CPU0_SA_DQ<31>")
	)
	(segment
		(start 309.338218 -271.425416)
		(end 309.338218 -272.100294)
		(width 0.18288)
		(layer "In4.Cu")
		(net "M_B_CPU0_SA_DQ<31>")
	)
	(segment
		(start 323.19214 -262.018526)
		(end 315.178694 -270.031972)
		(width 0.18288)
		(layer "In4.Cu")
		(net "M_B_CPU0_SA_DQ<31>")
	)
	(segment
		(start 305.454812 -273.960844)
		(end 305.17084 -273.676872)
		(width 0.18288)
		(layer "In4.Cu")
		(net "M_B_CPU0_SA_DQ<31>")
	)
	(segment
		(start 309.498238 -271.265396)
		(end 309.338218 -271.425416)
		(width 0.18288)
		(layer "In4.Cu")
		(net "M_B_CPU0_SA_DQ<31>")
	)
	(segment
		(start 315.178694 -270.031972)
		(end 313.866276 -270.031972)
		(width 0.18288)
		(layer "In4.Cu")
		(net "M_B_CPU0_SA_DQ<31>")
	)
	(segment
		(start 305.943508 -273.73072)
		(end 305.713384 -273.960844)
		(width 0.18288)
		(layer "In4.Cu")
		(net "M_B_CPU0_SA_DQ<31>")
	)
	(segment
		(start 301.694088 -275.545804)
		(end 300.796198 -276.443694)
		(width 0.18288)
		(layer "In4.Cu")
		(net "M_B_CPU0_SA_DQ<31>")
	)
	(segment
		(start 300.354492 -279.232868)
		(end 299.56379 -279.232868)
		(width 0.18288)
		(layer "In4.Cu")
		(net "M_B_CPU0_SA_DQ<31>")
	)
	(segment
		(start 337.332828 -260.749034)
		(end 337.322414 -260.75513)
		(width 0.088646)
		(layer "In4.Cu")
		(net "M_B_CPU0_SA_DQ<31>")
	)
	(segment
		(start 305.659536 -273.188176)
		(end 305.943508 -273.472148)
		(width 0.18288)
		(layer "In4.Cu")
		(net "M_B_CPU0_SA_DQ<31>")
	)
	(segment
		(start 340.151974 -260.749034)
		(end 340.14156 -260.75513)
		(width 0.088646)
		(layer "In4.Cu")
		(net "M_B_CPU0_SA_DQ<31>")
	)
	(arc
		(start 333.188564 -260.75513)
		(mid 332.905862 -260.679388)
		(end 332.62316 -260.75513)
		(width 0.088646)
		(layer "In4.Cu")
		(net "M_B_CPU0_SA_DQ<31>")
	)
	(arc
		(start 336.38236 -260.75513)
		(mid 336.195162 -260.805273)
		(end 336.007964 -260.75513)
		(width 0.088646)
		(layer "In4.Cu")
		(net "M_B_CPU0_SA_DQ<31>")
	)
	(arc
		(start 331.678534 -260.757924)
		(mid 331.493063 -260.794808)
		(end 331.323442 -260.711188)
		(width 0.088646)
		(layer "In4.Cu")
		(net "M_B_CPU0_SA_DQ<31>")
	)
	(arc
		(start 335.44256 -260.75513)
		(mid 335.255362 -260.805273)
		(end 335.068164 -260.75513)
		(width 0.088646)
		(layer "In4.Cu")
		(net "M_B_CPU0_SA_DQ<31>")
	)
	(arc
		(start 335.068164 -260.75513)
		(mid 334.785462 -260.679388)
		(end 334.50276 -260.75513)
		(width 0.088646)
		(layer "In4.Cu")
		(net "M_B_CPU0_SA_DQ<31>")
	)
	(arc
		(start 332.62316 -260.75513)
		(mid 332.435962 -260.805273)
		(end 332.248764 -260.75513)
		(width 0.088646)
		(layer "In4.Cu")
		(net "M_B_CPU0_SA_DQ<31>")
	)
	(arc
		(start 337.887564 -260.75513)
		(mid 337.611005 -260.679421)
		(end 337.332828 -260.749034)
		(width 0.088646)
		(layer "In4.Cu")
		(net "M_B_CPU0_SA_DQ<31>")
	)
	(arc
		(start 337.322414 -260.75513)
		(mid 337.135216 -260.805273)
		(end 336.948018 -260.75513)
		(width 0.088646)
		(layer "In4.Cu")
		(net "M_B_CPU0_SA_DQ<31>")
	)
	(arc
		(start 333.56296 -260.75513)
		(mid 333.375762 -260.805273)
		(end 333.188564 -260.75513)
		(width 0.088646)
		(layer "In4.Cu")
		(net "M_B_CPU0_SA_DQ<31>")
	)
	(arc
		(start 334.128364 -260.75513)
		(mid 333.845662 -260.679388)
		(end 333.56296 -260.75513)
		(width 0.088646)
		(layer "In4.Cu")
		(net "M_B_CPU0_SA_DQ<31>")
	)
	(arc
		(start 340.14156 -260.75513)
		(mid 339.954362 -260.805273)
		(end 339.767164 -260.75513)
		(width 0.088646)
		(layer "In4.Cu")
		(net "M_B_CPU0_SA_DQ<31>")
	)
	(arc
		(start 336.007964 -260.75513)
		(mid 335.725262 -260.679388)
		(end 335.44256 -260.75513)
		(width 0.088646)
		(layer "In4.Cu")
		(net "M_B_CPU0_SA_DQ<31>")
	)
	(arc
		(start 340.98611 -261.179564)
		(mid 340.896996 -260.934267)
		(end 340.707218 -260.75513)
		(width 0.088646)
		(layer "In4.Cu")
		(net "M_B_CPU0_SA_DQ<31>")
	)
	(arc
		(start 338.26196 -260.75513)
		(mid 338.074762 -260.805273)
		(end 337.887564 -260.75513)
		(width 0.088646)
		(layer "In4.Cu")
		(net "M_B_CPU0_SA_DQ<31>")
	)
	(arc
		(start 332.248764 -260.75513)
		(mid 331.966062 -260.679388)
		(end 331.68336 -260.75513)
		(width 0.088646)
		(layer "In4.Cu")
		(net "M_B_CPU0_SA_DQ<31>")
	)
	(arc
		(start 339.767164 -260.75513)
		(mid 339.490605 -260.679421)
		(end 339.212428 -260.749034)
		(width 0.088646)
		(layer "In4.Cu")
		(net "M_B_CPU0_SA_DQ<31>")
	)
	(arc
		(start 340.707218 -260.75513)
		(mid 340.430405 -260.679294)
		(end 340.151974 -260.749034)
		(width 0.088646)
		(layer "In4.Cu")
		(net "M_B_CPU0_SA_DQ<31>")
	)
	(arc
		(start 336.948018 -260.75513)
		(mid 336.671205 -260.679294)
		(end 336.392774 -260.749034)
		(width 0.088646)
		(layer "In4.Cu")
		(net "M_B_CPU0_SA_DQ<31>")
	)
	(arc
		(start 338.827618 -260.75513)
		(mid 338.550805 -260.679294)
		(end 338.272374 -260.749034)
		(width 0.088646)
		(layer "In4.Cu")
		(net "M_B_CPU0_SA_DQ<31>")
	)
	(arc
		(start 339.202014 -260.75513)
		(mid 339.014816 -260.805273)
		(end 338.827618 -260.75513)
		(width 0.088646)
		(layer "In4.Cu")
		(net "M_B_CPU0_SA_DQ<31>")
	)
	(arc
		(start 334.50276 -260.75513)
		(mid 334.315562 -260.805273)
		(end 334.128364 -260.75513)
		(width 0.088646)
		(layer "In4.Cu")
		(net "M_B_CPU0_SA_DQ<31>")
	)
	(segment
		(start 292.940486 -281.041856)
		(end 292.68547 -281.041856)
		(width 0.101854)
		(layer "F.Cu")
		(net "M_B_CPU0_SA_DQ<30>")
	)
	(segment
		(start 292.67531 -281.031696)
		(end 291.937948 -281.031696)
		(width 0.20066)
		(layer "F.Cu")
		(net "M_B_CPU0_SA_DQ<30>")
	)
	(segment
		(start 295.944544 -281.678634)
		(end 295.777158 -281.511248)
		(width 0.20066)
		(layer "F.Cu")
		(net "M_B_CPU0_SA_DQ<30>")
	)
	(segment
		(start 295.633394 -281.041856)
		(end 295.000426 -281.041856)
		(width 0.20066)
		(layer "F.Cu")
		(net "M_B_CPU0_SA_DQ<30>")
	)
	(segment
		(start 292.68547 -281.041856)
		(end 292.67531 -281.031696)
		(width 0.101854)
		(layer "F.Cu")
		(net "M_B_CPU0_SA_DQ<30>")
	)
	(segment
		(start 341.833962 -261.522718)
		(end 341.833962 -262.058404)
		(width 0.20066)
		(layer "F.Cu")
		(net "M_B_CPU0_SA_DQ<30>")
	)
	(segment
		(start 291.937948 -281.031696)
		(end 291.502846 -281.466798)
		(width 0.20066)
		(layer "F.Cu")
		(net "M_B_CPU0_SA_DQ<30>")
	)
	(segment
		(start 295.777158 -281.511248)
		(end 295.777158 -281.18562)
		(width 0.20066)
		(layer "F.Cu")
		(net "M_B_CPU0_SA_DQ<30>")
	)
	(segment
		(start 296.373042 -281.678634)
		(end 295.944544 -281.678634)
		(width 0.20066)
		(layer "F.Cu")
		(net "M_B_CPU0_SA_DQ<30>")
	)
	(segment
		(start 291.502846 -281.466798)
		(end 290.355782 -281.466798)
		(width 0.20066)
		(layer "F.Cu")
		(net "M_B_CPU0_SA_DQ<30>")
	)
	(segment
		(start 297.899582 -281.466798)
		(end 296.584878 -281.466798)
		(width 0.20066)
		(layer "F.Cu")
		(net "M_B_CPU0_SA_DQ<30>")
	)
	(segment
		(start 341.833962 -262.058404)
		(end 341.834216 -262.058658)
		(width 0.20066)
		(layer "F.Cu")
		(net "M_B_CPU0_SA_DQ<30>")
	)
	(segment
		(start 295.000426 -281.041856)
		(end 292.940486 -281.041856)
		(width 0.1016)
		(layer "F.Cu")
		(net "M_B_CPU0_SA_DQ<30>")
	)
	(segment
		(start 296.584878 -281.466798)
		(end 296.373042 -281.678634)
		(width 0.20066)
		(layer "F.Cu")
		(net "M_B_CPU0_SA_DQ<30>")
	)
	(segment
		(start 295.777158 -281.18562)
		(end 295.633394 -281.041856)
		(width 0.20066)
		(layer "F.Cu")
		(net "M_B_CPU0_SA_DQ<30>")
	)
	(segment
		(start 299.029882 -281.466798)
		(end 297.899582 -281.466798)
		(width 0.20066)
		(layer "F.Cu")
		(net "M_B_CPU0_SA_DQ<30>")
	)
	(segment
		(start 327.197212 -261.46506)
		(end 323.903086 -262.82904)
		(width 0.18288)
		(layer "In4.Cu")
		(net "M_B_CPU0_SA_DQ<30>")
	)
	(segment
		(start 299.566838 -280.929842)
		(end 299.029882 -281.466798)
		(width 0.18288)
		(layer "In4.Cu")
		(net "M_B_CPU0_SA_DQ<30>")
	)
	(segment
		(start 309.119778 -275.45157)
		(end 308.936898 -275.63445)
		(width 0.18288)
		(layer "In4.Cu")
		(net "M_B_CPU0_SA_DQ<30>")
	)
	(segment
		(start 323.903086 -262.82904)
		(end 320.23558 -266.496546)
		(width 0.18288)
		(layer "In4.Cu")
		(net "M_B_CPU0_SA_DQ<30>")
	)
	(segment
		(start 317.969392 -269.117318)
		(end 317.614808 -269.117318)
		(width 0.18288)
		(layer "In4.Cu")
		(net "M_B_CPU0_SA_DQ<30>")
	)
	(segment
		(start 305.621944 -276.819868)
		(end 305.128422 -276.326346)
		(width 0.18288)
		(layer "In4.Cu")
		(net "M_B_CPU0_SA_DQ<30>")
	)
	(segment
		(start 300.654974 -280.929842)
		(end 299.566838 -280.929842)
		(width 0.18288)
		(layer "In4.Cu")
		(net "M_B_CPU0_SA_DQ<30>")
	)
	(segment
		(start 316.326012 -270.406114)
		(end 316.326012 -270.760698)
		(width 0.18288)
		(layer "In4.Cu")
		(net "M_B_CPU0_SA_DQ<30>")
	)
	(segment
		(start 305.128422 -276.326346)
		(end 304.869342 -276.326346)
		(width 0.18288)
		(layer "In4.Cu")
		(net "M_B_CPU0_SA_DQ<30>")
	)
	(segment
		(start 331.38999 -261.46506)
		(end 330.724002 -261.46506)
		(width 0.088646)
		(layer "In4.Cu")
		(net "M_B_CPU0_SA_DQ<30>")
	)
	(segment
		(start 340.237064 -261.5692)
		(end 340.222332 -261.560564)
		(width 0.088646)
		(layer "In4.Cu")
		(net "M_B_CPU0_SA_DQ<30>")
	)
	(segment
		(start 316.326012 -270.760698)
		(end 316.014608 -271.072102)
		(width 0.18288)
		(layer "In4.Cu")
		(net "M_B_CPU0_SA_DQ<30>")
	)
	(segment
		(start 308.936898 -275.63445)
		(end 307.594254 -275.63445)
		(width 0.18288)
		(layer "In4.Cu")
		(net "M_B_CPU0_SA_DQ<30>")
	)
	(segment
		(start 304.619914 -276.575774)
		(end 304.619914 -276.801834)
		(width 0.18288)
		(layer "In4.Cu")
		(net "M_B_CPU0_SA_DQ<30>")
	)
	(segment
		(start 315.660024 -271.072102)
		(end 314.9473 -271.784826)
		(width 0.18288)
		(layer "In4.Cu")
		(net "M_B_CPU0_SA_DQ<30>")
	)
	(segment
		(start 306.970684 -276.25802)
		(end 306.409852 -276.25802)
		(width 0.18288)
		(layer "In4.Cu")
		(net "M_B_CPU0_SA_DQ<30>")
	)
	(segment
		(start 319.569592 -267.162534)
		(end 319.258188 -267.473938)
		(width 0.18288)
		(layer "In4.Cu")
		(net "M_B_CPU0_SA_DQ<30>")
	)
	(segment
		(start 317.614808 -269.117318)
		(end 317.303404 -269.428722)
		(width 0.18288)
		(layer "In4.Cu")
		(net "M_B_CPU0_SA_DQ<30>")
	)
	(segment
		(start 312.251852 -272.236184)
		(end 310.214772 -273.079972)
		(width 0.18288)
		(layer "In4.Cu")
		(net "M_B_CPU0_SA_DQ<30>")
	)
	(segment
		(start 305.129946 -277.311866)
		(end 305.129946 -277.537926)
		(width 0.18288)
		(layer "In4.Cu")
		(net "M_B_CPU0_SA_DQ<30>")
	)
	(segment
		(start 330.724002 -261.46506)
		(end 327.197212 -261.46506)
		(width 0.18288)
		(layer "In4.Cu")
		(net "M_B_CPU0_SA_DQ<30>")
	)
	(segment
		(start 341.269066 -261.623048)
		(end 341.176864 -261.5692)
		(width 0.088646)
		(layer "In4.Cu")
		(net "M_B_CPU0_SA_DQ<30>")
	)
	(segment
		(start 319.258188 -267.828522)
		(end 318.946784 -268.139926)
		(width 0.18288)
		(layer "In4.Cu")
		(net "M_B_CPU0_SA_DQ<30>")
	)
	(segment
		(start 304.851054 -277.816818)
		(end 303.767998 -277.816818)
		(width 0.18288)
		(layer "In4.Cu")
		(net "M_B_CPU0_SA_DQ<30>")
	)
	(segment
		(start 304.869342 -276.326346)
		(end 304.619914 -276.575774)
		(width 0.18288)
		(layer "In4.Cu")
		(net "M_B_CPU0_SA_DQ<30>")
	)
	(segment
		(start 309.119778 -275.022818)
		(end 309.119778 -275.45157)
		(width 0.18288)
		(layer "In4.Cu")
		(net "M_B_CPU0_SA_DQ<30>")
	)
	(segment
		(start 308.259226 -273.936206)
		(end 308.259226 -274.162266)
		(width 0.18288)
		(layer "In4.Cu")
		(net "M_B_CPU0_SA_DQ<30>")
	)
	(segment
		(start 309.604918 -273.689826)
		(end 308.505606 -273.689826)
		(width 0.18288)
		(layer "In4.Cu")
		(net "M_B_CPU0_SA_DQ<30>")
	)
	(segment
		(start 314.9473 -271.784826)
		(end 312.70321 -271.784826)
		(width 0.18288)
		(layer "In4.Cu")
		(net "M_B_CPU0_SA_DQ<30>")
	)
	(segment
		(start 341.176864 -261.5692)
		(end 341.162132 -261.560564)
		(width 0.088646)
		(layer "In4.Cu")
		(net "M_B_CPU0_SA_DQ<30>")
	)
	(segment
		(start 318.946784 -268.139926)
		(end 318.5922 -268.139926)
		(width 0.18288)
		(layer "In4.Cu")
		(net "M_B_CPU0_SA_DQ<30>")
	)
	(segment
		(start 318.280796 -268.45133)
		(end 318.280796 -268.805914)
		(width 0.18288)
		(layer "In4.Cu")
		(net "M_B_CPU0_SA_DQ<30>")
	)
	(segment
		(start 319.924176 -267.162534)
		(end 319.569592 -267.162534)
		(width 0.18288)
		(layer "In4.Cu")
		(net "M_B_CPU0_SA_DQ<30>")
	)
	(segment
		(start 319.258188 -267.473938)
		(end 319.258188 -267.828522)
		(width 0.18288)
		(layer "In4.Cu")
		(net "M_B_CPU0_SA_DQ<30>")
	)
	(segment
		(start 317.303404 -269.783306)
		(end 316.992 -270.09471)
		(width 0.18288)
		(layer "In4.Cu")
		(net "M_B_CPU0_SA_DQ<30>")
	)
	(segment
		(start 308.259226 -274.162266)
		(end 309.119778 -275.022818)
		(width 0.18288)
		(layer "In4.Cu")
		(net "M_B_CPU0_SA_DQ<30>")
	)
	(segment
		(start 320.23558 -266.85113)
		(end 319.924176 -267.162534)
		(width 0.18288)
		(layer "In4.Cu")
		(net "M_B_CPU0_SA_DQ<30>")
	)
	(segment
		(start 316.637416 -270.09471)
		(end 316.326012 -270.406114)
		(width 0.18288)
		(layer "In4.Cu")
		(net "M_B_CPU0_SA_DQ<30>")
	)
	(segment
		(start 305.129946 -277.537926)
		(end 304.851054 -277.816818)
		(width 0.18288)
		(layer "In4.Cu")
		(net "M_B_CPU0_SA_DQ<30>")
	)
	(segment
		(start 304.619914 -276.801834)
		(end 305.129946 -277.311866)
		(width 0.18288)
		(layer "In4.Cu")
		(net "M_B_CPU0_SA_DQ<30>")
	)
	(segment
		(start 307.594254 -275.63445)
		(end 306.970684 -276.25802)
		(width 0.18288)
		(layer "In4.Cu")
		(net "M_B_CPU0_SA_DQ<30>")
	)
	(segment
		(start 320.23558 -266.496546)
		(end 320.23558 -266.85113)
		(width 0.18288)
		(layer "In4.Cu")
		(net "M_B_CPU0_SA_DQ<30>")
	)
	(segment
		(start 305.848004 -276.819868)
		(end 305.621944 -276.819868)
		(width 0.18288)
		(layer "In4.Cu")
		(net "M_B_CPU0_SA_DQ<30>")
	)
	(segment
		(start 306.409852 -276.25802)
		(end 305.848004 -276.819868)
		(width 0.18288)
		(layer "In4.Cu")
		(net "M_B_CPU0_SA_DQ<30>")
	)
	(segment
		(start 317.303404 -269.428722)
		(end 317.303404 -269.783306)
		(width 0.18288)
		(layer "In4.Cu")
		(net "M_B_CPU0_SA_DQ<30>")
	)
	(segment
		(start 303.767998 -277.816818)
		(end 300.654974 -280.929842)
		(width 0.18288)
		(layer "In4.Cu")
		(net "M_B_CPU0_SA_DQ<30>")
	)
	(segment
		(start 316.992 -270.09471)
		(end 316.637416 -270.09471)
		(width 0.18288)
		(layer "In4.Cu")
		(net "M_B_CPU0_SA_DQ<30>")
	)
	(segment
		(start 318.280796 -268.805914)
		(end 317.969392 -269.117318)
		(width 0.18288)
		(layer "In4.Cu")
		(net "M_B_CPU0_SA_DQ<30>")
	)
	(segment
		(start 318.5922 -268.139926)
		(end 318.280796 -268.45133)
		(width 0.18288)
		(layer "In4.Cu")
		(net "M_B_CPU0_SA_DQ<30>")
	)
	(segment
		(start 308.505606 -273.689826)
		(end 308.259226 -273.936206)
		(width 0.18288)
		(layer "In4.Cu")
		(net "M_B_CPU0_SA_DQ<30>")
	)
	(segment
		(start 316.014608 -271.072102)
		(end 315.660024 -271.072102)
		(width 0.18288)
		(layer "In4.Cu")
		(net "M_B_CPU0_SA_DQ<30>")
	)
	(segment
		(start 310.214772 -273.079972)
		(end 309.604918 -273.689826)
		(width 0.18288)
		(layer "In4.Cu")
		(net "M_B_CPU0_SA_DQ<30>")
	)
	(segment
		(start 312.70321 -271.784826)
		(end 312.251852 -272.236184)
		(width 0.18288)
		(layer "In4.Cu")
		(net "M_B_CPU0_SA_DQ<30>")
	)
	(arc
		(start 335.538064 -261.5692)
		(mid 335.255362 -261.493424)
		(end 334.97266 -261.5692)
		(width 0.088646)
		(layer "In4.Cu")
		(net "M_B_CPU0_SA_DQ<30>")
	)
	(arc
		(start 337.79206 -261.5692)
		(mid 337.604862 -261.619343)
		(end 337.417664 -261.5692)
		(width 0.088646)
		(layer "In4.Cu")
		(net "M_B_CPU0_SA_DQ<30>")
	)
	(arc
		(start 339.297264 -261.5692)
		(mid 339.014562 -261.493424)
		(end 338.73186 -261.5692)
		(width 0.088646)
		(layer "In4.Cu")
		(net "M_B_CPU0_SA_DQ<30>")
	)
	(arc
		(start 341.162132 -261.560564)
		(mid 340.885657 -261.493244)
		(end 340.61146 -261.5692)
		(width 0.088646)
		(layer "In4.Cu")
		(net "M_B_CPU0_SA_DQ<30>")
	)
	(arc
		(start 332.15326 -261.5692)
		(mid 331.966062 -261.619343)
		(end 331.778864 -261.5692)
		(width 0.088646)
		(layer "In4.Cu")
		(net "M_B_CPU0_SA_DQ<30>")
	)
	(arc
		(start 336.477864 -261.5692)
		(mid 336.195162 -261.493424)
		(end 335.91246 -261.5692)
		(width 0.088646)
		(layer "In4.Cu")
		(net "M_B_CPU0_SA_DQ<30>")
	)
	(arc
		(start 338.357464 -261.5692)
		(mid 338.074762 -261.493424)
		(end 337.79206 -261.5692)
		(width 0.088646)
		(layer "In4.Cu")
		(net "M_B_CPU0_SA_DQ<30>")
	)
	(arc
		(start 334.598264 -261.5692)
		(mid 334.315562 -261.493424)
		(end 334.03286 -261.5692)
		(width 0.088646)
		(layer "In4.Cu")
		(net "M_B_CPU0_SA_DQ<30>")
	)
	(arc
		(start 331.778864 -261.5692)
		(mid 331.591285 -261.491508)
		(end 331.38999 -261.46506)
		(width 0.088646)
		(layer "In4.Cu")
		(net "M_B_CPU0_SA_DQ<30>")
	)
	(arc
		(start 340.61146 -261.5692)
		(mid 340.424262 -261.619343)
		(end 340.237064 -261.5692)
		(width 0.088646)
		(layer "In4.Cu")
		(net "M_B_CPU0_SA_DQ<30>")
	)
	(arc
		(start 341.834216 -262.058658)
		(mid 341.565673 -261.822648)
		(end 341.269066 -261.623048)
		(width 0.088646)
		(layer "In4.Cu")
		(net "M_B_CPU0_SA_DQ<30>")
	)
	(arc
		(start 338.73186 -261.5692)
		(mid 338.544662 -261.619343)
		(end 338.357464 -261.5692)
		(width 0.088646)
		(layer "In4.Cu")
		(net "M_B_CPU0_SA_DQ<30>")
	)
	(arc
		(start 333.09306 -261.5692)
		(mid 332.905862 -261.619343)
		(end 332.718664 -261.5692)
		(width 0.088646)
		(layer "In4.Cu")
		(net "M_B_CPU0_SA_DQ<30>")
	)
	(arc
		(start 335.91246 -261.5692)
		(mid 335.725262 -261.619343)
		(end 335.538064 -261.5692)
		(width 0.088646)
		(layer "In4.Cu")
		(net "M_B_CPU0_SA_DQ<30>")
	)
	(arc
		(start 333.658464 -261.5692)
		(mid 333.375762 -261.493424)
		(end 333.09306 -261.5692)
		(width 0.088646)
		(layer "In4.Cu")
		(net "M_B_CPU0_SA_DQ<30>")
	)
	(arc
		(start 337.417664 -261.5692)
		(mid 337.134962 -261.493424)
		(end 336.85226 -261.5692)
		(width 0.088646)
		(layer "In4.Cu")
		(net "M_B_CPU0_SA_DQ<30>")
	)
	(arc
		(start 334.97266 -261.5692)
		(mid 334.785462 -261.619343)
		(end 334.598264 -261.5692)
		(width 0.088646)
		(layer "In4.Cu")
		(net "M_B_CPU0_SA_DQ<30>")
	)
	(arc
		(start 334.03286 -261.5692)
		(mid 333.845662 -261.619343)
		(end 333.658464 -261.5692)
		(width 0.088646)
		(layer "In4.Cu")
		(net "M_B_CPU0_SA_DQ<30>")
	)
	(arc
		(start 339.67166 -261.5692)
		(mid 339.484462 -261.619343)
		(end 339.297264 -261.5692)
		(width 0.088646)
		(layer "In4.Cu")
		(net "M_B_CPU0_SA_DQ<30>")
	)
	(arc
		(start 336.85226 -261.5692)
		(mid 336.665062 -261.619343)
		(end 336.477864 -261.5692)
		(width 0.088646)
		(layer "In4.Cu")
		(net "M_B_CPU0_SA_DQ<30>")
	)
	(arc
		(start 332.718664 -261.5692)
		(mid 332.435962 -261.493424)
		(end 332.15326 -261.5692)
		(width 0.088646)
		(layer "In4.Cu")
		(net "M_B_CPU0_SA_DQ<30>")
	)
	(arc
		(start 340.222332 -261.560564)
		(mid 339.945857 -261.493244)
		(end 339.67166 -261.5692)
		(width 0.088646)
		(layer "In4.Cu")
		(net "M_B_CPU0_SA_DQ<30>")
	)
	(segment
		(start 296.584878 -315.46673)
		(end 297.899582 -315.46673)
		(width 0.20066)
		(layer "F.Cu")
		(net "M_B_CPU0_SA_DQ<2>")
	)
	(segment
		(start 299.0215 -315.46673)
		(end 297.899582 -315.46673)
		(width 0.20066)
		(layer "F.Cu")
		(net "M_B_CPU0_SA_DQ<2>")
	)
	(segment
		(start 295.633394 -315.041788)
		(end 295.777158 -315.185552)
		(width 0.20066)
		(layer "F.Cu")
		(net "M_B_CPU0_SA_DQ<2>")
	)
	(segment
		(start 295.944544 -315.678566)
		(end 296.373042 -315.678566)
		(width 0.20066)
		(layer "F.Cu")
		(net "M_B_CPU0_SA_DQ<2>")
	)
	(segment
		(start 295.777158 -315.51118)
		(end 295.944544 -315.678566)
		(width 0.20066)
		(layer "F.Cu")
		(net "M_B_CPU0_SA_DQ<2>")
	)
	(segment
		(start 292.940486 -315.041788)
		(end 295.000426 -315.041788)
		(width 0.1016)
		(layer "F.Cu")
		(net "M_B_CPU0_SA_DQ<2>")
	)
	(segment
		(start 292.67531 -315.031628)
		(end 292.68547 -315.041788)
		(width 0.101854)
		(layer "F.Cu")
		(net "M_B_CPU0_SA_DQ<2>")
	)
	(segment
		(start 338.074762 -276.172676)
		(end 338.074762 -276.708616)
		(width 0.20066)
		(layer "F.Cu")
		(net "M_B_CPU0_SA_DQ<2>")
	)
	(segment
		(start 296.373042 -315.678566)
		(end 296.584878 -315.46673)
		(width 0.20066)
		(layer "F.Cu")
		(net "M_B_CPU0_SA_DQ<2>")
	)
	(segment
		(start 292.68547 -315.041788)
		(end 292.940486 -315.041788)
		(width 0.101854)
		(layer "F.Cu")
		(net "M_B_CPU0_SA_DQ<2>")
	)
	(segment
		(start 291.7571 -315.031628)
		(end 292.67531 -315.031628)
		(width 0.20066)
		(layer "F.Cu")
		(net "M_B_CPU0_SA_DQ<2>")
	)
	(segment
		(start 291.321998 -315.46673)
		(end 291.7571 -315.031628)
		(width 0.20066)
		(layer "F.Cu")
		(net "M_B_CPU0_SA_DQ<2>")
	)
	(segment
		(start 295.777158 -315.185552)
		(end 295.777158 -315.51118)
		(width 0.20066)
		(layer "F.Cu")
		(net "M_B_CPU0_SA_DQ<2>")
	)
	(segment
		(start 290.355782 -315.46673)
		(end 291.321998 -315.46673)
		(width 0.20066)
		(layer "F.Cu")
		(net "M_B_CPU0_SA_DQ<2>")
	)
	(segment
		(start 295.000426 -315.041788)
		(end 295.633394 -315.041788)
		(width 0.20066)
		(layer "F.Cu")
		(net "M_B_CPU0_SA_DQ<2>")
	)
	(segment
		(start 337.700112 -278.336502)
		(end 337.700112 -278.346408)
		(width 0.088646)
		(layer "In2.Cu")
		(net "M_B_CPU0_SA_DQ<2>")
	)
	(segment
		(start 299.037502 -315.46673)
		(end 299.0215 -315.46673)
		(width 0.18288)
		(layer "In2.Cu")
		(net "M_B_CPU0_SA_DQ<2>")
	)
	(segment
		(start 329.817222 -289.752278)
		(end 325.348854 -300.54042)
		(width 0.18288)
		(layer "In2.Cu")
		(net "M_B_CPU0_SA_DQ<2>")
	)
	(segment
		(start 337.794092 -276.708616)
		(end 337.709764 -276.792944)
		(width 0.088646)
		(layer "In2.Cu")
		(net "M_B_CPU0_SA_DQ<2>")
	)
	(segment
		(start 299.646086 -318.314324)
		(end 299.646086 -316.568328)
		(width 0.18288)
		(layer "In2.Cu")
		(net "M_B_CPU0_SA_DQ<2>")
	)
	(segment
		(start 302.532288 -318.507364)
		(end 301.875698 -318.507364)
		(width 0.18288)
		(layer "In2.Cu")
		(net "M_B_CPU0_SA_DQ<2>")
	)
	(segment
		(start 332.323186 -287.246314)
		(end 329.817222 -289.752278)
		(width 0.18288)
		(layer "In2.Cu")
		(net "M_B_CPU0_SA_DQ<2>")
	)
	(segment
		(start 301.682658 -318.314324)
		(end 301.682658 -317.565024)
		(width 0.18288)
		(layer "In2.Cu")
		(net "M_B_CPU0_SA_DQ<2>")
	)
	(segment
		(start 334.604614 -282.077922)
		(end 334.598518 -282.081478)
		(width 0.088646)
		(layer "In2.Cu")
		(net "M_B_CPU0_SA_DQ<2>")
	)
	(segment
		(start 308.255162 -317.593472)
		(end 305.047142 -317.593472)
		(width 0.18288)
		(layer "In2.Cu")
		(net "M_B_CPU0_SA_DQ<2>")
	)
	(segment
		(start 301.682658 -317.565024)
		(end 301.489618 -317.371984)
		(width 0.18288)
		(layer "In2.Cu")
		(net "M_B_CPU0_SA_DQ<2>")
	)
	(segment
		(start 323.337428 -307.112162)
		(end 315.625226 -314.824364)
		(width 0.18288)
		(layer "In2.Cu")
		(net "M_B_CPU0_SA_DQ<2>")
	)
	(segment
		(start 337.887564 -278.012144)
		(end 337.878674 -278.017224)
		(width 0.088646)
		(layer "In2.Cu")
		(net "M_B_CPU0_SA_DQ<2>")
	)
	(segment
		(start 301.177198 -317.371984)
		(end 300.979078 -317.570104)
		(width 0.18288)
		(layer "In2.Cu")
		(net "M_B_CPU0_SA_DQ<2>")
	)
	(segment
		(start 336.290412 -280.778204)
		(end 336.290412 -280.78811)
		(width 0.088646)
		(layer "In2.Cu")
		(net "M_B_CPU0_SA_DQ<2>")
	)
	(segment
		(start 335.453228 -281.273758)
		(end 335.442814 -281.267662)
		(width 0.088646)
		(layer "In2.Cu")
		(net "M_B_CPU0_SA_DQ<2>")
	)
	(segment
		(start 337.417664 -278.82596)
		(end 337.408774 -278.83104)
		(width 0.088646)
		(layer "In2.Cu")
		(net "M_B_CPU0_SA_DQ<2>")
	)
	(segment
		(start 337.230212 -279.150318)
		(end 337.230212 -279.160224)
		(width 0.088646)
		(layer "In2.Cu")
		(net "M_B_CPU0_SA_DQ<2>")
	)
	(segment
		(start 333.546196 -282.030932)
		(end 332.90891 -282.668218)
		(width 0.088646)
		(layer "In2.Cu")
		(net "M_B_CPU0_SA_DQ<2>")
	)
	(segment
		(start 300.979078 -318.314324)
		(end 300.786038 -318.507364)
		(width 0.18288)
		(layer "In2.Cu")
		(net "M_B_CPU0_SA_DQ<2>")
	)
	(segment
		(start 325.348854 -300.54042)
		(end 324.692518 -303.840896)
		(width 0.18288)
		(layer "In2.Cu")
		(net "M_B_CPU0_SA_DQ<2>")
	)
	(segment
		(start 301.875698 -318.507364)
		(end 301.682658 -318.314324)
		(width 0.18288)
		(layer "In2.Cu")
		(net "M_B_CPU0_SA_DQ<2>")
	)
	(segment
		(start 324.692518 -303.840896)
		(end 323.337428 -307.112162)
		(width 0.18288)
		(layer "In2.Cu")
		(net "M_B_CPU0_SA_DQ<2>")
	)
	(segment
		(start 337.887564 -277.032974)
		(end 337.899756 -277.040086)
		(width 0.088646)
		(layer "In2.Cu")
		(net "M_B_CPU0_SA_DQ<2>")
	)
	(segment
		(start 315.625226 -314.824364)
		(end 315.625226 -315.124084)
		(width 0.18288)
		(layer "In2.Cu")
		(net "M_B_CPU0_SA_DQ<2>")
	)
	(segment
		(start 315.625226 -315.124084)
		(end 314.518802 -316.230508)
		(width 0.18288)
		(layer "In2.Cu")
		(net "M_B_CPU0_SA_DQ<2>")
	)
	(segment
		(start 338.074762 -276.708616)
		(end 337.794092 -276.708616)
		(width 0.088646)
		(layer "In2.Cu")
		(net "M_B_CPU0_SA_DQ<2>")
	)
	(segment
		(start 304.94859 -317.49492)
		(end 303.544732 -317.49492)
		(width 0.18288)
		(layer "In2.Cu")
		(net "M_B_CPU0_SA_DQ<2>")
	)
	(segment
		(start 301.489618 -317.371984)
		(end 301.177198 -317.371984)
		(width 0.18288)
		(layer "In2.Cu")
		(net "M_B_CPU0_SA_DQ<2>")
	)
	(segment
		(start 336.760312 -279.964134)
		(end 336.760312 -279.982676)
		(width 0.088646)
		(layer "In2.Cu")
		(net "M_B_CPU0_SA_DQ<2>")
	)
	(segment
		(start 332.90891 -282.668218)
		(end 332.851506 -282.725622)
		(width 0.18288)
		(layer "In2.Cu")
		(net "M_B_CPU0_SA_DQ<2>")
	)
	(segment
		(start 314.272676 -316.74181)
		(end 312.170064 -316.74181)
		(width 0.18288)
		(layer "In2.Cu")
		(net "M_B_CPU0_SA_DQ<2>")
	)
	(segment
		(start 336.477864 -280.453846)
		(end 336.468974 -280.458926)
		(width 0.088646)
		(layer "In2.Cu")
		(net "M_B_CPU0_SA_DQ<2>")
	)
	(segment
		(start 312.170064 -316.74181)
		(end 311.540906 -317.370968)
		(width 0.18288)
		(layer "In2.Cu")
		(net "M_B_CPU0_SA_DQ<2>")
	)
	(segment
		(start 300.979078 -317.570104)
		(end 300.979078 -318.314324)
		(width 0.18288)
		(layer "In2.Cu")
		(net "M_B_CPU0_SA_DQ<2>")
	)
	(segment
		(start 311.540906 -317.370968)
		(end 310.979312 -317.603632)
		(width 0.18288)
		(layer "In2.Cu")
		(net "M_B_CPU0_SA_DQ<2>")
	)
	(segment
		(start 299.646086 -316.568328)
		(end 299.297344 -315.726572)
		(width 0.18288)
		(layer "In2.Cu")
		(net "M_B_CPU0_SA_DQ<2>")
	)
	(segment
		(start 299.297344 -315.726572)
		(end 299.037502 -315.46673)
		(width 0.18288)
		(layer "In2.Cu")
		(net "M_B_CPU0_SA_DQ<2>")
	)
	(segment
		(start 308.546754 -317.30188)
		(end 308.255162 -317.593472)
		(width 0.18288)
		(layer "In2.Cu")
		(net "M_B_CPU0_SA_DQ<2>")
	)
	(segment
		(start 332.851506 -285.97098)
		(end 332.706472 -286.321246)
		(width 0.18288)
		(layer "In2.Cu")
		(net "M_B_CPU0_SA_DQ<2>")
	)
	(segment
		(start 299.839126 -318.507364)
		(end 299.646086 -318.314324)
		(width 0.18288)
		(layer "In2.Cu")
		(net "M_B_CPU0_SA_DQ<2>")
	)
	(segment
		(start 337.878674 -277.027894)
		(end 337.887564 -277.032974)
		(width 0.088646)
		(layer "In2.Cu")
		(net "M_B_CPU0_SA_DQ<2>")
	)
	(segment
		(start 305.047142 -317.593472)
		(end 304.94859 -317.49492)
		(width 0.18288)
		(layer "In2.Cu")
		(net "M_B_CPU0_SA_DQ<2>")
	)
	(segment
		(start 300.786038 -318.507364)
		(end 299.839126 -318.507364)
		(width 0.18288)
		(layer "In2.Cu")
		(net "M_B_CPU0_SA_DQ<2>")
	)
	(segment
		(start 335.068418 -281.267662)
		(end 335.059528 -281.272742)
		(width 0.088646)
		(layer "In2.Cu")
		(net "M_B_CPU0_SA_DQ<2>")
	)
	(segment
		(start 332.851506 -282.725622)
		(end 332.851506 -285.97098)
		(width 0.18288)
		(layer "In2.Cu")
		(net "M_B_CPU0_SA_DQ<2>")
	)
	(segment
		(start 308.938422 -317.30188)
		(end 308.546754 -317.30188)
		(width 0.18288)
		(layer "In2.Cu")
		(net "M_B_CPU0_SA_DQ<2>")
	)
	(segment
		(start 337.895438 -278.007318)
		(end 337.887564 -278.012144)
		(width 0.088646)
		(layer "In2.Cu")
		(net "M_B_CPU0_SA_DQ<2>")
	)
	(segment
		(start 303.544732 -317.49492)
		(end 302.532288 -318.507364)
		(width 0.18288)
		(layer "In2.Cu")
		(net "M_B_CPU0_SA_DQ<2>")
	)
	(segment
		(start 309.240174 -317.603632)
		(end 308.938422 -317.30188)
		(width 0.18288)
		(layer "In2.Cu")
		(net "M_B_CPU0_SA_DQ<2>")
	)
	(segment
		(start 310.979312 -317.603632)
		(end 309.240174 -317.603632)
		(width 0.18288)
		(layer "In2.Cu")
		(net "M_B_CPU0_SA_DQ<2>")
	)
	(segment
		(start 336.947764 -279.639776)
		(end 336.938874 -279.644856)
		(width 0.088646)
		(layer "In2.Cu")
		(net "M_B_CPU0_SA_DQ<2>")
	)
	(segment
		(start 332.706472 -286.321246)
		(end 332.323186 -287.246314)
		(width 0.18288)
		(layer "In2.Cu")
		(net "M_B_CPU0_SA_DQ<2>")
	)
	(segment
		(start 314.518802 -316.230508)
		(end 314.518802 -316.495684)
		(width 0.18288)
		(layer "In2.Cu")
		(net "M_B_CPU0_SA_DQ<2>")
	)
	(segment
		(start 333.845662 -282.030932)
		(end 333.546196 -282.030932)
		(width 0.088646)
		(layer "In2.Cu")
		(net "M_B_CPU0_SA_DQ<2>")
	)
	(segment
		(start 314.518802 -316.495684)
		(end 314.272676 -316.74181)
		(width 0.18288)
		(layer "In2.Cu")
		(net "M_B_CPU0_SA_DQ<2>")
	)
	(arc
		(start 334.598518 -282.081478)
		(mid 334.321705 -282.157348)
		(end 334.043274 -282.087574)
		(width 0.088646)
		(layer "In2.Cu")
		(net "M_B_CPU0_SA_DQ<2>")
	)
	(arc
		(start 336.007964 -281.267662)
		(mid 335.731405 -281.343405)
		(end 335.453228 -281.273758)
		(width 0.088646)
		(layer "In2.Cu")
		(net "M_B_CPU0_SA_DQ<2>")
	)
	(arc
		(start 336.938874 -279.644856)
		(mid 336.80796 -279.781216)
		(end 336.760312 -279.964134)
		(width 0.088646)
		(layer "In2.Cu")
		(net "M_B_CPU0_SA_DQ<2>")
	)
	(arc
		(start 337.408774 -278.83104)
		(mid 337.27786 -278.9674)
		(end 337.230212 -279.150318)
		(width 0.088646)
		(layer "In2.Cu")
		(net "M_B_CPU0_SA_DQ<2>")
	)
	(arc
		(start 334.043274 -282.087574)
		(mid 333.94843 -282.045423)
		(end 333.845662 -282.030932)
		(width 0.088646)
		(layer "In2.Cu")
		(net "M_B_CPU0_SA_DQ<2>")
	)
	(arc
		(start 334.880966 -281.59202)
		(mid 334.80705 -281.871522)
		(end 334.604614 -282.077922)
		(width 0.088646)
		(layer "In2.Cu")
		(net "M_B_CPU0_SA_DQ<2>")
	)
	(arc
		(start 337.878674 -278.017224)
		(mid 337.74776 -278.153584)
		(end 337.700112 -278.336502)
		(width 0.088646)
		(layer "In2.Cu")
		(net "M_B_CPU0_SA_DQ<2>")
	)
	(arc
		(start 337.709764 -276.792944)
		(mid 337.770645 -276.927358)
		(end 337.878674 -277.027894)
		(width 0.088646)
		(layer "In2.Cu")
		(net "M_B_CPU0_SA_DQ<2>")
	)
	(arc
		(start 335.059528 -281.272742)
		(mid 334.928614 -281.409102)
		(end 334.880966 -281.59202)
		(width 0.088646)
		(layer "In2.Cu")
		(net "M_B_CPU0_SA_DQ<2>")
	)
	(arc
		(start 337.899756 -277.040086)
		(mid 338.097984 -277.245934)
		(end 338.170266 -277.522432)
		(width 0.088646)
		(layer "In2.Cu")
		(net "M_B_CPU0_SA_DQ<2>")
	)
	(arc
		(start 335.442814 -281.267662)
		(mid 335.255616 -281.217519)
		(end 335.068418 -281.267662)
		(width 0.088646)
		(layer "In2.Cu")
		(net "M_B_CPU0_SA_DQ<2>")
	)
	(arc
		(start 336.290412 -280.78811)
		(mid 336.212301 -281.065059)
		(end 336.007964 -281.267662)
		(width 0.088646)
		(layer "In2.Cu")
		(net "M_B_CPU0_SA_DQ<2>")
	)
	(arc
		(start 336.760312 -279.982676)
		(mid 336.68015 -280.254865)
		(end 336.477864 -280.453846)
		(width 0.088646)
		(layer "In2.Cu")
		(net "M_B_CPU0_SA_DQ<2>")
	)
	(arc
		(start 337.230212 -279.160224)
		(mid 337.152101 -279.437173)
		(end 336.947764 -279.639776)
		(width 0.088646)
		(layer "In2.Cu")
		(net "M_B_CPU0_SA_DQ<2>")
	)
	(arc
		(start 338.170266 -277.522432)
		(mid 338.096781 -277.801108)
		(end 337.895438 -278.007318)
		(width 0.088646)
		(layer "In2.Cu")
		(net "M_B_CPU0_SA_DQ<2>")
	)
	(arc
		(start 336.468974 -280.458926)
		(mid 336.33806 -280.595286)
		(end 336.290412 -280.778204)
		(width 0.088646)
		(layer "In2.Cu")
		(net "M_B_CPU0_SA_DQ<2>")
	)
	(arc
		(start 337.700112 -278.346408)
		(mid 337.622001 -278.623357)
		(end 337.417664 -278.82596)
		(width 0.088646)
		(layer "In2.Cu")
		(net "M_B_CPU0_SA_DQ<2>")
	)
	(segment
		(start 287.801304 -280.827988)
		(end 287.589976 -280.61666)
		(width 0.20066)
		(layer "F.Cu")
		(net "M_B_CPU0_SA_DQ<29>")
	)
	(segment
		(start 294.904414 -280.61666)
		(end 293.799514 -280.61666)
		(width 0.20066)
		(layer "F.Cu")
		(net "M_B_CPU0_SA_DQ<29>")
	)
	(segment
		(start 340.424516 -260.708902)
		(end 340.424516 -261.244588)
		(width 0.20066)
		(layer "F.Cu")
		(net "M_B_CPU0_SA_DQ<29>")
	)
	(segment
		(start 292.160198 -280.61666)
		(end 291.735256 -280.191718)
		(width 0.20066)
		(layer "F.Cu")
		(net "M_B_CPU0_SA_DQ<29>")
	)
	(segment
		(start 288.305748 -280.827988)
		(end 287.801304 -280.827988)
		(width 0.20066)
		(layer "F.Cu")
		(net "M_B_CPU0_SA_DQ<29>")
	)
	(segment
		(start 293.799514 -280.61666)
		(end 292.160198 -280.61666)
		(width 0.20066)
		(layer "F.Cu")
		(net "M_B_CPU0_SA_DQ<29>")
	)
	(segment
		(start 289.240468 -280.191718)
		(end 289.231578 -280.182828)
		(width 0.1016)
		(layer "F.Cu")
		(net "M_B_CPU0_SA_DQ<29>")
	)
	(segment
		(start 288.46018 -280.345388)
		(end 288.46018 -280.673556)
		(width 0.20066)
		(layer "F.Cu")
		(net "M_B_CPU0_SA_DQ<29>")
	)
	(segment
		(start 287.589976 -280.61666)
		(end 286.255714 -280.61666)
		(width 0.20066)
		(layer "F.Cu")
		(net "M_B_CPU0_SA_DQ<29>")
	)
	(segment
		(start 291.556694 -280.191718)
		(end 291.225986 -280.191718)
		(width 0.101854)
		(layer "F.Cu")
		(net "M_B_CPU0_SA_DQ<29>")
	)
	(segment
		(start 288.62274 -280.182828)
		(end 288.46018 -280.345388)
		(width 0.20066)
		(layer "F.Cu")
		(net "M_B_CPU0_SA_DQ<29>")
	)
	(segment
		(start 291.225986 -280.191718)
		(end 289.240468 -280.191718)
		(width 0.1016)
		(layer "F.Cu")
		(net "M_B_CPU0_SA_DQ<29>")
	)
	(segment
		(start 291.735256 -280.191718)
		(end 291.556694 -280.191718)
		(width 0.20066)
		(layer "F.Cu")
		(net "M_B_CPU0_SA_DQ<29>")
	)
	(segment
		(start 288.46018 -280.673556)
		(end 288.305748 -280.827988)
		(width 0.20066)
		(layer "F.Cu")
		(net "M_B_CPU0_SA_DQ<29>")
	)
	(segment
		(start 340.424516 -261.244588)
		(end 340.424262 -261.244842)
		(width 0.20066)
		(layer "F.Cu")
		(net "M_B_CPU0_SA_DQ<29>")
	)
	(segment
		(start 289.231578 -280.182828)
		(end 288.62274 -280.182828)
		(width 0.20066)
		(layer "F.Cu")
		(net "M_B_CPU0_SA_DQ<29>")
	)
	(segment
		(start 331.259688 -260.996176)
		(end 331.230732 -260.96722)
		(width 0.088646)
		(layer "In4.Cu")
		(net "M_B_CPU0_SA_DQ<29>")
	)
	(segment
		(start 298.275756 -280.008838)
		(end 298.275756 -279.635458)
		(width 0.18288)
		(layer "In4.Cu")
		(net "M_B_CPU0_SA_DQ<29>")
	)
	(segment
		(start 297.401996 -280.191718)
		(end 297.076876 -280.191718)
		(width 0.18288)
		(layer "In4.Cu")
		(net "M_B_CPU0_SA_DQ<29>")
	)
	(segment
		(start 300.497748 -280.191718)
		(end 298.458636 -280.191718)
		(width 0.18288)
		(layer "In4.Cu")
		(net "M_B_CPU0_SA_DQ<29>")
	)
	(segment
		(start 339.297264 -260.920484)
		(end 339.282532 -260.92912)
		(width 0.088646)
		(layer "In4.Cu")
		(net "M_B_CPU0_SA_DQ<29>")
	)
	(segment
		(start 308.510178 -272.83029)
		(end 307.058314 -273.431762)
		(width 0.18288)
		(layer "In4.Cu")
		(net "M_B_CPU0_SA_DQ<29>")
	)
	(segment
		(start 295.329356 -280.191718)
		(end 294.904414 -280.61666)
		(width 0.18288)
		(layer "In4.Cu")
		(net "M_B_CPU0_SA_DQ<29>")
	)
	(segment
		(start 337.417664 -260.920484)
		(end 337.402932 -260.92912)
		(width 0.088646)
		(layer "In4.Cu")
		(net "M_B_CPU0_SA_DQ<29>")
	)
	(segment
		(start 296.203116 -280.008838)
		(end 296.020236 -280.191718)
		(width 0.18288)
		(layer "In4.Cu")
		(net "M_B_CPU0_SA_DQ<29>")
	)
	(segment
		(start 313.199526 -270.565626)
		(end 311.94756 -271.817592)
		(width 0.18288)
		(layer "In4.Cu")
		(net "M_B_CPU0_SA_DQ<29>")
	)
	(segment
		(start 301.542704 -279.146762)
		(end 300.497748 -280.191718)
		(width 0.18288)
		(layer "In4.Cu")
		(net "M_B_CPU0_SA_DQ<29>")
	)
	(segment
		(start 340.62035 -260.925564)
		(end 340.61146 -260.920484)
		(width 0.088646)
		(layer "In4.Cu")
		(net "M_B_CPU0_SA_DQ<29>")
	)
	(segment
		(start 311.94756 -271.817592)
		(end 309.502556 -272.83029)
		(width 0.18288)
		(layer "In4.Cu")
		(net "M_B_CPU0_SA_DQ<29>")
	)
	(segment
		(start 331.496162 -260.996176)
		(end 331.259688 -260.996176)
		(width 0.088646)
		(layer "In4.Cu")
		(net "M_B_CPU0_SA_DQ<29>")
	)
	(segment
		(start 298.092876 -279.452578)
		(end 297.767756 -279.452578)
		(width 0.18288)
		(layer "In4.Cu")
		(net "M_B_CPU0_SA_DQ<29>")
	)
	(segment
		(start 298.275756 -279.635458)
		(end 298.092876 -279.452578)
		(width 0.18288)
		(layer "In4.Cu")
		(net "M_B_CPU0_SA_DQ<29>")
	)
	(segment
		(start 296.203116 -279.635458)
		(end 296.203116 -280.008838)
		(width 0.18288)
		(layer "In4.Cu")
		(net "M_B_CPU0_SA_DQ<29>")
	)
	(segment
		(start 296.893996 -279.635458)
		(end 296.711116 -279.452578)
		(width 0.18288)
		(layer "In4.Cu")
		(net "M_B_CPU0_SA_DQ<29>")
	)
	(segment
		(start 297.767756 -279.452578)
		(end 297.584876 -279.635458)
		(width 0.18288)
		(layer "In4.Cu")
		(net "M_B_CPU0_SA_DQ<29>")
	)
	(segment
		(start 309.502556 -272.83029)
		(end 308.510178 -272.83029)
		(width 0.18288)
		(layer "In4.Cu")
		(net "M_B_CPU0_SA_DQ<29>")
	)
	(segment
		(start 301.542704 -277.857712)
		(end 301.542704 -279.146762)
		(width 0.18288)
		(layer "In4.Cu")
		(net "M_B_CPU0_SA_DQ<29>")
	)
	(segment
		(start 315.393324 -270.565626)
		(end 313.199526 -270.565626)
		(width 0.18288)
		(layer "In4.Cu")
		(net "M_B_CPU0_SA_DQ<29>")
	)
	(segment
		(start 296.893996 -280.008838)
		(end 296.893996 -279.635458)
		(width 0.18288)
		(layer "In4.Cu")
		(net "M_B_CPU0_SA_DQ<29>")
	)
	(segment
		(start 307.058314 -273.431762)
		(end 303.269904 -277.220172)
		(width 0.18288)
		(layer "In4.Cu")
		(net "M_B_CPU0_SA_DQ<29>")
	)
	(segment
		(start 296.711116 -279.452578)
		(end 296.385996 -279.452578)
		(width 0.18288)
		(layer "In4.Cu")
		(net "M_B_CPU0_SA_DQ<29>")
	)
	(segment
		(start 323.540628 -262.418322)
		(end 315.393324 -270.565626)
		(width 0.18288)
		(layer "In4.Cu")
		(net "M_B_CPU0_SA_DQ<29>")
	)
	(segment
		(start 340.736936 -261.244842)
		(end 340.79434 -261.187438)
		(width 0.088646)
		(layer "In4.Cu")
		(net "M_B_CPU0_SA_DQ<29>")
	)
	(segment
		(start 298.458636 -280.191718)
		(end 298.275756 -280.008838)
		(width 0.18288)
		(layer "In4.Cu")
		(net "M_B_CPU0_SA_DQ<29>")
	)
	(segment
		(start 330.724002 -260.96722)
		(end 327.044558 -260.96722)
		(width 0.18288)
		(layer "In4.Cu")
		(net "M_B_CPU0_SA_DQ<29>")
	)
	(segment
		(start 327.044558 -260.96722)
		(end 323.540628 -262.418322)
		(width 0.18288)
		(layer "In4.Cu")
		(net "M_B_CPU0_SA_DQ<29>")
	)
	(segment
		(start 297.076876 -280.191718)
		(end 296.893996 -280.008838)
		(width 0.18288)
		(layer "In4.Cu")
		(net "M_B_CPU0_SA_DQ<29>")
	)
	(segment
		(start 296.385996 -279.452578)
		(end 296.203116 -279.635458)
		(width 0.18288)
		(layer "In4.Cu")
		(net "M_B_CPU0_SA_DQ<29>")
	)
	(segment
		(start 302.180244 -277.220172)
		(end 301.542704 -277.857712)
		(width 0.18288)
		(layer "In4.Cu")
		(net "M_B_CPU0_SA_DQ<29>")
	)
	(segment
		(start 297.584876 -280.008838)
		(end 297.401996 -280.191718)
		(width 0.18288)
		(layer "In4.Cu")
		(net "M_B_CPU0_SA_DQ<29>")
	)
	(segment
		(start 296.020236 -280.191718)
		(end 295.329356 -280.191718)
		(width 0.18288)
		(layer "In4.Cu")
		(net "M_B_CPU0_SA_DQ<29>")
	)
	(segment
		(start 303.269904 -277.220172)
		(end 302.180244 -277.220172)
		(width 0.18288)
		(layer "In4.Cu")
		(net "M_B_CPU0_SA_DQ<29>")
	)
	(segment
		(start 340.424262 -261.244842)
		(end 340.736936 -261.244842)
		(width 0.088646)
		(layer "In4.Cu")
		(net "M_B_CPU0_SA_DQ<29>")
	)
	(segment
		(start 297.584876 -279.635458)
		(end 297.584876 -280.008838)
		(width 0.18288)
		(layer "In4.Cu")
		(net "M_B_CPU0_SA_DQ<29>")
	)
	(segment
		(start 331.230732 -260.96722)
		(end 330.724002 -260.96722)
		(width 0.088646)
		(layer "In4.Cu")
		(net "M_B_CPU0_SA_DQ<29>")
	)
	(arc
		(start 339.67166 -260.920484)
		(mid 339.484462 -260.870341)
		(end 339.297264 -260.920484)
		(width 0.088646)
		(layer "In4.Cu")
		(net "M_B_CPU0_SA_DQ<29>")
	)
	(arc
		(start 340.61146 -260.920484)
		(mid 340.424262 -260.870341)
		(end 340.237064 -260.920484)
		(width 0.088646)
		(layer "In4.Cu")
		(net "M_B_CPU0_SA_DQ<29>")
	)
	(arc
		(start 338.357464 -260.920484)
		(mid 338.074762 -260.996226)
		(end 337.79206 -260.920484)
		(width 0.088646)
		(layer "In4.Cu")
		(net "M_B_CPU0_SA_DQ<29>")
	)
	(arc
		(start 337.402932 -260.92912)
		(mid 337.126491 -260.996286)
		(end 336.85226 -260.920484)
		(width 0.088646)
		(layer "In4.Cu")
		(net "M_B_CPU0_SA_DQ<29>")
	)
	(arc
		(start 340.237064 -260.920484)
		(mid 339.954362 -260.996226)
		(end 339.67166 -260.920484)
		(width 0.088646)
		(layer "In4.Cu")
		(net "M_B_CPU0_SA_DQ<29>")
	)
	(arc
		(start 334.03286 -260.920484)
		(mid 333.845662 -260.870341)
		(end 333.658464 -260.920484)
		(width 0.088646)
		(layer "In4.Cu")
		(net "M_B_CPU0_SA_DQ<29>")
	)
	(arc
		(start 336.85226 -260.920484)
		(mid 336.665062 -260.870341)
		(end 336.477864 -260.920484)
		(width 0.088646)
		(layer "In4.Cu")
		(net "M_B_CPU0_SA_DQ<29>")
	)
	(arc
		(start 333.09306 -260.920484)
		(mid 332.905862 -260.870341)
		(end 332.718664 -260.920484)
		(width 0.088646)
		(layer "In4.Cu")
		(net "M_B_CPU0_SA_DQ<29>")
	)
	(arc
		(start 335.538064 -260.920484)
		(mid 335.255362 -260.996226)
		(end 334.97266 -260.920484)
		(width 0.088646)
		(layer "In4.Cu")
		(net "M_B_CPU0_SA_DQ<29>")
	)
	(arc
		(start 331.778864 -260.920484)
		(mid 331.642498 -260.976962)
		(end 331.496162 -260.996176)
		(width 0.088646)
		(layer "In4.Cu")
		(net "M_B_CPU0_SA_DQ<29>")
	)
	(arc
		(start 334.97266 -260.920484)
		(mid 334.785462 -260.870341)
		(end 334.598264 -260.920484)
		(width 0.088646)
		(layer "In4.Cu")
		(net "M_B_CPU0_SA_DQ<29>")
	)
	(arc
		(start 334.598264 -260.920484)
		(mid 334.315562 -260.996226)
		(end 334.03286 -260.920484)
		(width 0.088646)
		(layer "In4.Cu")
		(net "M_B_CPU0_SA_DQ<29>")
	)
	(arc
		(start 338.73186 -260.920484)
		(mid 338.544662 -260.870341)
		(end 338.357464 -260.920484)
		(width 0.088646)
		(layer "In4.Cu")
		(net "M_B_CPU0_SA_DQ<29>")
	)
	(arc
		(start 333.658464 -260.920484)
		(mid 333.375762 -260.996226)
		(end 333.09306 -260.920484)
		(width 0.088646)
		(layer "In4.Cu")
		(net "M_B_CPU0_SA_DQ<29>")
	)
	(arc
		(start 336.477864 -260.920484)
		(mid 336.195162 -260.996226)
		(end 335.91246 -260.920484)
		(width 0.088646)
		(layer "In4.Cu")
		(net "M_B_CPU0_SA_DQ<29>")
	)
	(arc
		(start 340.79434 -261.187438)
		(mid 340.736184 -261.037325)
		(end 340.62035 -260.925564)
		(width 0.088646)
		(layer "In4.Cu")
		(net "M_B_CPU0_SA_DQ<29>")
	)
	(arc
		(start 332.15326 -260.920484)
		(mid 331.966062 -260.870341)
		(end 331.778864 -260.920484)
		(width 0.088646)
		(layer "In4.Cu")
		(net "M_B_CPU0_SA_DQ<29>")
	)
	(arc
		(start 337.79206 -260.920484)
		(mid 337.604862 -260.870341)
		(end 337.417664 -260.920484)
		(width 0.088646)
		(layer "In4.Cu")
		(net "M_B_CPU0_SA_DQ<29>")
	)
	(arc
		(start 339.282532 -260.92912)
		(mid 339.006091 -260.996286)
		(end 338.73186 -260.920484)
		(width 0.088646)
		(layer "In4.Cu")
		(net "M_B_CPU0_SA_DQ<29>")
	)
	(arc
		(start 332.718664 -260.920484)
		(mid 332.435962 -260.996226)
		(end 332.15326 -260.920484)
		(width 0.088646)
		(layer "In4.Cu")
		(net "M_B_CPU0_SA_DQ<29>")
	)
	(arc
		(start 335.91246 -260.920484)
		(mid 335.725262 -260.870341)
		(end 335.538064 -260.920484)
		(width 0.088646)
		(layer "In4.Cu")
		(net "M_B_CPU0_SA_DQ<29>")
	)
	(segment
		(start 339.954362 -261.522718)
		(end 339.954362 -262.058404)
		(width 0.20066)
		(layer "F.Cu")
		(net "M_B_CPU0_SA_DQ<28>")
	)
	(segment
		(start 292.430454 -282.316682)
		(end 292.005512 -281.89174)
		(width 0.20066)
		(layer "F.Cu")
		(net "M_B_CPU0_SA_DQ<28>")
	)
	(segment
		(start 287.589976 -282.316682)
		(end 286.255714 -282.316682)
		(width 0.20066)
		(layer "F.Cu")
		(net "M_B_CPU0_SA_DQ<28>")
	)
	(segment
		(start 293.799514 -282.316682)
		(end 292.430454 -282.316682)
		(width 0.20066)
		(layer "F.Cu")
		(net "M_B_CPU0_SA_DQ<28>")
	)
	(segment
		(start 289.48761 -281.89174)
		(end 289.239706 -281.89174)
		(width 0.101854)
		(layer "F.Cu")
		(net "M_B_CPU0_SA_DQ<28>")
	)
	(segment
		(start 289.231578 -281.883612)
		(end 288.66973 -281.883612)
		(width 0.20066)
		(layer "F.Cu")
		(net "M_B_CPU0_SA_DQ<28>")
	)
	(segment
		(start 288.28746 -282.555442)
		(end 287.828736 -282.555442)
		(width 0.20066)
		(layer "F.Cu")
		(net "M_B_CPU0_SA_DQ<28>")
	)
	(segment
		(start 287.828736 -282.555442)
		(end 287.589976 -282.316682)
		(width 0.20066)
		(layer "F.Cu")
		(net "M_B_CPU0_SA_DQ<28>")
	)
	(segment
		(start 288.46018 -282.382722)
		(end 288.28746 -282.555442)
		(width 0.20066)
		(layer "F.Cu")
		(net "M_B_CPU0_SA_DQ<28>")
	)
	(segment
		(start 289.239706 -281.89174)
		(end 289.231578 -281.883612)
		(width 0.101854)
		(layer "F.Cu")
		(net "M_B_CPU0_SA_DQ<28>")
	)
	(segment
		(start 288.46018 -282.093162)
		(end 288.46018 -282.382722)
		(width 0.20066)
		(layer "F.Cu")
		(net "M_B_CPU0_SA_DQ<28>")
	)
	(segment
		(start 339.954362 -262.058404)
		(end 339.954616 -262.058658)
		(width 0.20066)
		(layer "F.Cu")
		(net "M_B_CPU0_SA_DQ<28>")
	)
	(segment
		(start 291.556694 -281.89174)
		(end 289.48761 -281.89174)
		(width 0.1016)
		(layer "F.Cu")
		(net "M_B_CPU0_SA_DQ<28>")
	)
	(segment
		(start 294.904414 -282.316682)
		(end 293.799514 -282.316682)
		(width 0.20066)
		(layer "F.Cu")
		(net "M_B_CPU0_SA_DQ<28>")
	)
	(segment
		(start 288.66973 -281.883612)
		(end 288.46018 -282.093162)
		(width 0.20066)
		(layer "F.Cu")
		(net "M_B_CPU0_SA_DQ<28>")
	)
	(segment
		(start 292.005512 -281.89174)
		(end 291.556694 -281.89174)
		(width 0.20066)
		(layer "F.Cu")
		(net "M_B_CPU0_SA_DQ<28>")
	)
	(segment
		(start 331.496162 -261.683754)
		(end 331.175614 -261.683754)
		(width 0.088646)
		(layer "In4.Cu")
		(net "M_B_CPU0_SA_DQ<28>")
	)
	(segment
		(start 297.584876 -281.70886)
		(end 297.401996 -281.89174)
		(width 0.18288)
		(layer "In4.Cu")
		(net "M_B_CPU0_SA_DQ<28>")
	)
	(segment
		(start 315.497718 -272.335752)
		(end 312.95848 -272.335752)
		(width 0.18288)
		(layer "In4.Cu")
		(net "M_B_CPU0_SA_DQ<28>")
	)
	(segment
		(start 324.827646 -263.005824)
		(end 315.497718 -272.335752)
		(width 0.18288)
		(layer "In4.Cu")
		(net "M_B_CPU0_SA_DQ<28>")
	)
	(segment
		(start 296.893996 -281.70886)
		(end 296.893996 -281.265884)
		(width 0.18288)
		(layer "In4.Cu")
		(net "M_B_CPU0_SA_DQ<28>")
	)
	(segment
		(start 303.259998 -279.834594)
		(end 302.824388 -280.270204)
		(width 0.18288)
		(layer "In4.Cu")
		(net "M_B_CPU0_SA_DQ<28>")
	)
	(segment
		(start 327.346056 -261.9629)
		(end 324.827646 -263.005824)
		(width 0.18288)
		(layer "In4.Cu")
		(net "M_B_CPU0_SA_DQ<28>")
	)
	(segment
		(start 304.023776 -278.359616)
		(end 303.259998 -279.123394)
		(width 0.18288)
		(layer "In4.Cu")
		(net "M_B_CPU0_SA_DQ<28>")
	)
	(segment
		(start 307.48097 -277.068026)
		(end 306.18938 -278.359616)
		(width 0.18288)
		(layer "In4.Cu")
		(net "M_B_CPU0_SA_DQ<28>")
	)
	(segment
		(start 331.175614 -261.683754)
		(end 330.896468 -261.9629)
		(width 0.088646)
		(layer "In4.Cu")
		(net "M_B_CPU0_SA_DQ<28>")
	)
	(segment
		(start 296.203116 -281.265884)
		(end 296.203116 -281.70886)
		(width 0.18288)
		(layer "In4.Cu")
		(net "M_B_CPU0_SA_DQ<28>")
	)
	(segment
		(start 339.584284 -261.958328)
		(end 339.20176 -261.7343)
		(width 0.088646)
		(layer "In4.Cu")
		(net "M_B_CPU0_SA_DQ<28>")
	)
	(segment
		(start 297.584876 -281.265884)
		(end 297.584876 -281.70886)
		(width 0.18288)
		(layer "In4.Cu")
		(net "M_B_CPU0_SA_DQ<28>")
	)
	(segment
		(start 296.385996 -281.083004)
		(end 296.203116 -281.265884)
		(width 0.18288)
		(layer "In4.Cu")
		(net "M_B_CPU0_SA_DQ<28>")
	)
	(segment
		(start 296.893996 -281.265884)
		(end 296.711116 -281.083004)
		(width 0.18288)
		(layer "In4.Cu")
		(net "M_B_CPU0_SA_DQ<28>")
	)
	(segment
		(start 330.724002 -261.9629)
		(end 327.346056 -261.9629)
		(width 0.18288)
		(layer "In4.Cu")
		(net "M_B_CPU0_SA_DQ<28>")
	)
	(segment
		(start 296.203116 -281.70886)
		(end 296.020236 -281.89174)
		(width 0.18288)
		(layer "In4.Cu")
		(net "M_B_CPU0_SA_DQ<28>")
	)
	(segment
		(start 302.63465 -280.270204)
		(end 301.013114 -281.89174)
		(width 0.18288)
		(layer "In4.Cu")
		(net "M_B_CPU0_SA_DQ<28>")
	)
	(segment
		(start 301.013114 -281.89174)
		(end 298.458636 -281.89174)
		(width 0.18288)
		(layer "In4.Cu")
		(net "M_B_CPU0_SA_DQ<28>")
	)
	(segment
		(start 296.020236 -281.89174)
		(end 295.329356 -281.89174)
		(width 0.18288)
		(layer "In4.Cu")
		(net "M_B_CPU0_SA_DQ<28>")
	)
	(segment
		(start 297.076876 -281.89174)
		(end 296.893996 -281.70886)
		(width 0.18288)
		(layer "In4.Cu")
		(net "M_B_CPU0_SA_DQ<28>")
	)
	(segment
		(start 298.092876 -281.083004)
		(end 297.767756 -281.083004)
		(width 0.18288)
		(layer "In4.Cu")
		(net "M_B_CPU0_SA_DQ<28>")
	)
	(segment
		(start 308.226206 -277.068026)
		(end 307.48097 -277.068026)
		(width 0.18288)
		(layer "In4.Cu")
		(net "M_B_CPU0_SA_DQ<28>")
	)
	(segment
		(start 296.711116 -281.083004)
		(end 296.385996 -281.083004)
		(width 0.18288)
		(layer "In4.Cu")
		(net "M_B_CPU0_SA_DQ<28>")
	)
	(segment
		(start 312.95848 -272.335752)
		(end 308.226206 -277.068026)
		(width 0.18288)
		(layer "In4.Cu")
		(net "M_B_CPU0_SA_DQ<28>")
	)
	(segment
		(start 298.458636 -281.89174)
		(end 298.275756 -281.70886)
		(width 0.18288)
		(layer "In4.Cu")
		(net "M_B_CPU0_SA_DQ<28>")
	)
	(segment
		(start 298.275756 -281.70886)
		(end 298.275756 -281.265884)
		(width 0.18288)
		(layer "In4.Cu")
		(net "M_B_CPU0_SA_DQ<28>")
	)
	(segment
		(start 295.329356 -281.89174)
		(end 294.904414 -282.316682)
		(width 0.18288)
		(layer "In4.Cu")
		(net "M_B_CPU0_SA_DQ<28>")
	)
	(segment
		(start 298.275756 -281.265884)
		(end 298.092876 -281.083004)
		(width 0.18288)
		(layer "In4.Cu")
		(net "M_B_CPU0_SA_DQ<28>")
	)
	(segment
		(start 303.259998 -279.123394)
		(end 303.259998 -279.834594)
		(width 0.18288)
		(layer "In4.Cu")
		(net "M_B_CPU0_SA_DQ<28>")
	)
	(segment
		(start 330.896468 -261.9629)
		(end 330.724002 -261.9629)
		(width 0.088646)
		(layer "In4.Cu")
		(net "M_B_CPU0_SA_DQ<28>")
	)
	(segment
		(start 306.18938 -278.359616)
		(end 304.023776 -278.359616)
		(width 0.18288)
		(layer "In4.Cu")
		(net "M_B_CPU0_SA_DQ<28>")
	)
	(segment
		(start 297.767756 -281.083004)
		(end 297.584876 -281.265884)
		(width 0.18288)
		(layer "In4.Cu")
		(net "M_B_CPU0_SA_DQ<28>")
	)
	(segment
		(start 302.824388 -280.270204)
		(end 302.63465 -280.270204)
		(width 0.18288)
		(layer "In4.Cu")
		(net "M_B_CPU0_SA_DQ<28>")
	)
	(segment
		(start 297.401996 -281.89174)
		(end 297.076876 -281.89174)
		(width 0.18288)
		(layer "In4.Cu")
		(net "M_B_CPU0_SA_DQ<28>")
	)
	(arc
		(start 335.068164 -261.7343)
		(mid 334.785462 -261.810076)
		(end 334.50276 -261.7343)
		(width 0.088646)
		(layer "In4.Cu")
		(net "M_B_CPU0_SA_DQ<28>")
	)
	(arc
		(start 338.26196 -261.7343)
		(mid 338.074762 -261.684157)
		(end 337.887564 -261.7343)
		(width 0.088646)
		(layer "In4.Cu")
		(net "M_B_CPU0_SA_DQ<28>")
	)
	(arc
		(start 336.007964 -261.7343)
		(mid 335.725262 -261.810076)
		(end 335.44256 -261.7343)
		(width 0.088646)
		(layer "In4.Cu")
		(net "M_B_CPU0_SA_DQ<28>")
	)
	(arc
		(start 333.56296 -261.7343)
		(mid 333.375762 -261.684157)
		(end 333.188564 -261.7343)
		(width 0.088646)
		(layer "In4.Cu")
		(net "M_B_CPU0_SA_DQ<28>")
	)
	(arc
		(start 331.68336 -261.7343)
		(mid 331.593088 -261.696701)
		(end 331.496162 -261.683754)
		(width 0.088646)
		(layer "In4.Cu")
		(net "M_B_CPU0_SA_DQ<28>")
	)
	(arc
		(start 334.128364 -261.7343)
		(mid 333.845662 -261.810076)
		(end 333.56296 -261.7343)
		(width 0.088646)
		(layer "In4.Cu")
		(net "M_B_CPU0_SA_DQ<28>")
	)
	(arc
		(start 336.38236 -261.7343)
		(mid 336.195162 -261.684157)
		(end 336.007964 -261.7343)
		(width 0.088646)
		(layer "In4.Cu")
		(net "M_B_CPU0_SA_DQ<28>")
	)
	(arc
		(start 333.188564 -261.7343)
		(mid 332.905862 -261.810076)
		(end 332.62316 -261.7343)
		(width 0.088646)
		(layer "In4.Cu")
		(net "M_B_CPU0_SA_DQ<28>")
	)
	(arc
		(start 337.32216 -261.7343)
		(mid 337.134962 -261.684157)
		(end 336.947764 -261.7343)
		(width 0.088646)
		(layer "In4.Cu")
		(net "M_B_CPU0_SA_DQ<28>")
	)
	(arc
		(start 332.248764 -261.7343)
		(mid 331.966062 -261.810076)
		(end 331.68336 -261.7343)
		(width 0.088646)
		(layer "In4.Cu")
		(net "M_B_CPU0_SA_DQ<28>")
	)
	(arc
		(start 335.44256 -261.7343)
		(mid 335.255362 -261.684157)
		(end 335.068164 -261.7343)
		(width 0.088646)
		(layer "In4.Cu")
		(net "M_B_CPU0_SA_DQ<28>")
	)
	(arc
		(start 336.947764 -261.7343)
		(mid 336.665062 -261.810076)
		(end 336.38236 -261.7343)
		(width 0.088646)
		(layer "In4.Cu")
		(net "M_B_CPU0_SA_DQ<28>")
	)
	(arc
		(start 339.20176 -261.7343)
		(mid 339.014562 -261.684157)
		(end 338.827364 -261.7343)
		(width 0.088646)
		(layer "In4.Cu")
		(net "M_B_CPU0_SA_DQ<28>")
	)
	(arc
		(start 339.954616 -262.058658)
		(mid 339.76276 -262.033175)
		(end 339.584284 -261.958328)
		(width 0.088646)
		(layer "In4.Cu")
		(net "M_B_CPU0_SA_DQ<28>")
	)
	(arc
		(start 332.62316 -261.7343)
		(mid 332.435962 -261.684157)
		(end 332.248764 -261.7343)
		(width 0.088646)
		(layer "In4.Cu")
		(net "M_B_CPU0_SA_DQ<28>")
	)
	(arc
		(start 334.50276 -261.7343)
		(mid 334.315562 -261.684157)
		(end 334.128364 -261.7343)
		(width 0.088646)
		(layer "In4.Cu")
		(net "M_B_CPU0_SA_DQ<28>")
	)
	(arc
		(start 338.827364 -261.7343)
		(mid 338.544662 -261.810076)
		(end 338.26196 -261.7343)
		(width 0.088646)
		(layer "In4.Cu")
		(net "M_B_CPU0_SA_DQ<28>")
	)
	(arc
		(start 337.887564 -261.7343)
		(mid 337.604862 -261.810076)
		(end 337.32216 -261.7343)
		(width 0.088646)
		(layer "In4.Cu")
		(net "M_B_CPU0_SA_DQ<28>")
	)
	(segment
		(start 292.178994 -286.013398)
		(end 292.178994 -285.84271)
		(width 0.20066)
		(layer "F.Cu")
		(net "M_B_CPU0_SA_DQ<27>")
	)
	(segment
		(start 295.693846 -285.99257)
		(end 295.544748 -286.141668)
		(width 0.20066)
		(layer "F.Cu")
		(net "M_B_CPU0_SA_DQ<27>")
	)
	(segment
		(start 297.08348 -285.716726)
		(end 296.875962 -285.924244)
		(width 0.20066)
		(layer "F.Cu")
		(net "M_B_CPU0_SA_DQ<27>")
	)
	(segment
		(start 295.693846 -285.840932)
		(end 295.693846 -285.99257)
		(width 0.20066)
		(layer "F.Cu")
		(net "M_B_CPU0_SA_DQ<27>")
	)
	(segment
		(start 292.689534 -286.141668)
		(end 292.67531 -286.155892)
		(width 0.101854)
		(layer "F.Cu")
		(net "M_B_CPU0_SA_DQ<27>")
	)
	(segment
		(start 295.000426 -286.141668)
		(end 292.927532 -286.141668)
		(width 0.1016)
		(layer "F.Cu")
		(net "M_B_CPU0_SA_DQ<27>")
	)
	(segment
		(start 341.833962 -263.150604)
		(end 341.833962 -263.68629)
		(width 0.20066)
		(layer "F.Cu")
		(net "M_B_CPU0_SA_DQ<27>")
	)
	(segment
		(start 296.875962 -285.924244)
		(end 296.42943 -285.924244)
		(width 0.20066)
		(layer "F.Cu")
		(net "M_B_CPU0_SA_DQ<27>")
	)
	(segment
		(start 292.927532 -286.141668)
		(end 292.689534 -286.141668)
		(width 0.101854)
		(layer "F.Cu")
		(net "M_B_CPU0_SA_DQ<27>")
	)
	(segment
		(start 292.178994 -285.84271)
		(end 292.05301 -285.716726)
		(width 0.20066)
		(layer "F.Cu")
		(net "M_B_CPU0_SA_DQ<27>")
	)
	(segment
		(start 292.05301 -285.716726)
		(end 290.355782 -285.716726)
		(width 0.20066)
		(layer "F.Cu")
		(net "M_B_CPU0_SA_DQ<27>")
	)
	(segment
		(start 292.67531 -286.155892)
		(end 292.321488 -286.155892)
		(width 0.20066)
		(layer "F.Cu")
		(net "M_B_CPU0_SA_DQ<27>")
	)
	(segment
		(start 295.544748 -286.141668)
		(end 295.000426 -286.141668)
		(width 0.20066)
		(layer "F.Cu")
		(net "M_B_CPU0_SA_DQ<27>")
	)
	(segment
		(start 292.321488 -286.155892)
		(end 292.178994 -286.013398)
		(width 0.20066)
		(layer "F.Cu")
		(net "M_B_CPU0_SA_DQ<27>")
	)
	(segment
		(start 299.004482 -285.716726)
		(end 297.899582 -285.716726)
		(width 0.20066)
		(layer "F.Cu")
		(net "M_B_CPU0_SA_DQ<27>")
	)
	(segment
		(start 297.899582 -285.716726)
		(end 297.08348 -285.716726)
		(width 0.20066)
		(layer "F.Cu")
		(net "M_B_CPU0_SA_DQ<27>")
	)
	(segment
		(start 341.833962 -263.68629)
		(end 341.834216 -263.686544)
		(width 0.20066)
		(layer "F.Cu")
		(net "M_B_CPU0_SA_DQ<27>")
	)
	(segment
		(start 296.217594 -285.712408)
		(end 295.82237 -285.712408)
		(width 0.20066)
		(layer "F.Cu")
		(net "M_B_CPU0_SA_DQ<27>")
	)
	(segment
		(start 295.82237 -285.712408)
		(end 295.693846 -285.840932)
		(width 0.20066)
		(layer "F.Cu")
		(net "M_B_CPU0_SA_DQ<27>")
	)
	(segment
		(start 296.42943 -285.924244)
		(end 296.217594 -285.712408)
		(width 0.20066)
		(layer "F.Cu")
		(net "M_B_CPU0_SA_DQ<27>")
	)
	(segment
		(start 308.440328 -281.505152)
		(end 307.890164 -282.055316)
		(width 0.18288)
		(layer "In4.Cu")
		(net "M_B_CPU0_SA_DQ<27>")
	)
	(segment
		(start 311.596532 -279.555448)
		(end 311.370472 -279.555448)
		(width 0.18288)
		(layer "In4.Cu")
		(net "M_B_CPU0_SA_DQ<27>")
	)
	(segment
		(start 304.985166 -282.798012)
		(end 304.592228 -282.798012)
		(width 0.18288)
		(layer "In4.Cu")
		(net "M_B_CPU0_SA_DQ<27>")
	)
	(segment
		(start 338.833206 -264.014204)
		(end 338.827364 -264.010902)
		(width 0.088646)
		(layer "In4.Cu")
		(net "M_B_CPU0_SA_DQ<27>")
	)
	(segment
		(start 311.370472 -279.555448)
		(end 311.08523 -279.270206)
		(width 0.18288)
		(layer "In4.Cu")
		(net "M_B_CPU0_SA_DQ<27>")
	)
	(segment
		(start 330.724256 -264.07618)
		(end 327.99782 -264.07618)
		(width 0.18288)
		(layer "In4.Cu")
		(net "M_B_CPU0_SA_DQ<27>")
	)
	(segment
		(start 340.83244 -263.295384)
		(end 340.017354 -263.295384)
		(width 0.088646)
		(layer "In4.Cu")
		(net "M_B_CPU0_SA_DQ<27>")
	)
	(segment
		(start 304.403506 -283.411422)
		(end 304.14341 -283.671518)
		(width 0.18288)
		(layer "In4.Cu")
		(net "M_B_CPU0_SA_DQ<27>")
	)
	(segment
		(start 309.731918 -280.316686)
		(end 309.473346 -280.316686)
		(width 0.18288)
		(layer "In4.Cu")
		(net "M_B_CPU0_SA_DQ<27>")
	)
	(segment
		(start 341.47633 -263.590532)
		(end 341.085424 -263.364472)
		(width 0.088646)
		(layer "In4.Cu")
		(net "M_B_CPU0_SA_DQ<27>")
	)
	(segment
		(start 305.858926 -282.278328)
		(end 305.676046 -282.095448)
		(width 0.18288)
		(layer "In4.Cu")
		(net "M_B_CPU0_SA_DQ<27>")
	)
	(segment
		(start 336.953098 -264.014204)
		(end 336.947764 -264.010902)
		(width 0.088646)
		(layer "In4.Cu")
		(net "M_B_CPU0_SA_DQ<27>")
	)
	(segment
		(start 326.642476 -264.63752)
		(end 314.684664 -276.595332)
		(width 0.18288)
		(layer "In4.Cu")
		(net "M_B_CPU0_SA_DQ<27>")
	)
	(segment
		(start 310.594756 -279.53462)
		(end 310.594756 -279.76068)
		(width 0.18288)
		(layer "In4.Cu")
		(net "M_B_CPU0_SA_DQ<27>")
	)
	(segment
		(start 305.168046 -282.615132)
		(end 304.985166 -282.798012)
		(width 0.18288)
		(layer "In4.Cu")
		(net "M_B_CPU0_SA_DQ<27>")
	)
	(segment
		(start 339.773006 -263.35863)
		(end 339.767164 -263.361932)
		(width 0.088646)
		(layer "In4.Cu")
		(net "M_B_CPU0_SA_DQ<27>")
	)
	(segment
		(start 310.879998 -280.271982)
		(end 310.64454 -280.50744)
		(width 0.18288)
		(layer "In4.Cu")
		(net "M_B_CPU0_SA_DQ<27>")
	)
	(segment
		(start 309.473346 -280.316686)
		(end 309.243222 -280.54681)
		(width 0.18288)
		(layer "In4.Cu")
		(net "M_B_CPU0_SA_DQ<27>")
	)
	(segment
		(start 314.02274 -276.595332)
		(end 313.552078 -277.065994)
		(width 0.18288)
		(layer "In4.Cu")
		(net "M_B_CPU0_SA_DQ<27>")
	)
	(segment
		(start 313.552078 -277.065994)
		(end 313.552078 -277.667974)
		(width 0.18288)
		(layer "In4.Cu")
		(net "M_B_CPU0_SA_DQ<27>")
	)
	(segment
		(start 304.592228 -282.798012)
		(end 304.403506 -282.986734)
		(width 0.18288)
		(layer "In4.Cu")
		(net "M_B_CPU0_SA_DQ<27>")
	)
	(segment
		(start 303.022254 -284.393894)
		(end 300.86681 -285.286958)
		(width 0.18288)
		(layer "In4.Cu")
		(net "M_B_CPU0_SA_DQ<27>")
	)
	(segment
		(start 310.879998 -280.045922)
		(end 310.879998 -280.271982)
		(width 0.18288)
		(layer "In4.Cu")
		(net "M_B_CPU0_SA_DQ<27>")
	)
	(segment
		(start 299.004736 -285.71698)
		(end 299.004482 -285.716726)
		(width 0.18288)
		(layer "In4.Cu")
		(net "M_B_CPU0_SA_DQ<27>")
	)
	(segment
		(start 299.782738 -285.448756)
		(end 299.514514 -285.71698)
		(width 0.18288)
		(layer "In4.Cu")
		(net "M_B_CPU0_SA_DQ<27>")
	)
	(segment
		(start 338.827364 -264.010902)
		(end 338.821522 -264.007346)
		(width 0.088646)
		(layer "In4.Cu")
		(net "M_B_CPU0_SA_DQ<27>")
	)
	(segment
		(start 309.243222 -280.805382)
		(end 309.433976 -280.996136)
		(width 0.18288)
		(layer "In4.Cu")
		(net "M_B_CPU0_SA_DQ<27>")
	)
	(segment
		(start 314.684664 -276.595332)
		(end 314.02274 -276.595332)
		(width 0.18288)
		(layer "In4.Cu")
		(net "M_B_CPU0_SA_DQ<27>")
	)
	(segment
		(start 311.66943 -279.48255)
		(end 311.596532 -279.555448)
		(width 0.18288)
		(layer "In4.Cu")
		(net "M_B_CPU0_SA_DQ<27>")
	)
	(segment
		(start 306.68722 -282.798012)
		(end 306.041806 -282.798012)
		(width 0.18288)
		(layer "In4.Cu")
		(net "M_B_CPU0_SA_DQ<27>")
	)
	(segment
		(start 309.183532 -281.505152)
		(end 308.440328 -281.505152)
		(width 0.18288)
		(layer "In4.Cu")
		(net "M_B_CPU0_SA_DQ<27>")
	)
	(segment
		(start 305.168046 -282.278328)
		(end 305.168046 -282.615132)
		(width 0.18288)
		(layer "In4.Cu")
		(net "M_B_CPU0_SA_DQ<27>")
	)
	(segment
		(start 305.858926 -282.615132)
		(end 305.858926 -282.278328)
		(width 0.18288)
		(layer "In4.Cu")
		(net "M_B_CPU0_SA_DQ<27>")
	)
	(segment
		(start 312.99277 -278.561038)
		(end 312.071258 -279.48255)
		(width 0.18288)
		(layer "In4.Cu")
		(net "M_B_CPU0_SA_DQ<27>")
	)
	(segment
		(start 313.552078 -277.667974)
		(end 312.99277 -278.227282)
		(width 0.18288)
		(layer "In4.Cu")
		(net "M_B_CPU0_SA_DQ<27>")
	)
	(segment
		(start 304.14341 -283.671518)
		(end 303.74463 -283.671518)
		(width 0.18288)
		(layer "In4.Cu")
		(net "M_B_CPU0_SA_DQ<27>")
	)
	(segment
		(start 339.767164 -263.361932)
		(end 339.761322 -263.365488)
		(width 0.088646)
		(layer "In4.Cu")
		(net "M_B_CPU0_SA_DQ<27>")
	)
	(segment
		(start 299.514514 -285.71698)
		(end 299.004736 -285.71698)
		(width 0.18288)
		(layer "In4.Cu")
		(net "M_B_CPU0_SA_DQ<27>")
	)
	(segment
		(start 310.85917 -279.270206)
		(end 310.594756 -279.53462)
		(width 0.18288)
		(layer "In4.Cu")
		(net "M_B_CPU0_SA_DQ<27>")
	)
	(segment
		(start 309.922672 -280.50744)
		(end 309.731918 -280.316686)
		(width 0.18288)
		(layer "In4.Cu")
		(net "M_B_CPU0_SA_DQ<27>")
	)
	(segment
		(start 312.071258 -279.48255)
		(end 311.66943 -279.48255)
		(width 0.18288)
		(layer "In4.Cu")
		(net "M_B_CPU0_SA_DQ<27>")
	)
	(segment
		(start 327.99782 -264.07618)
		(end 326.642476 -264.63752)
		(width 0.18288)
		(layer "In4.Cu")
		(net "M_B_CPU0_SA_DQ<27>")
	)
	(segment
		(start 309.243222 -280.54681)
		(end 309.243222 -280.805382)
		(width 0.18288)
		(layer "In4.Cu")
		(net "M_B_CPU0_SA_DQ<27>")
	)
	(segment
		(start 309.433976 -280.996136)
		(end 309.433976 -281.254708)
		(width 0.18288)
		(layer "In4.Cu")
		(net "M_B_CPU0_SA_DQ<27>")
	)
	(segment
		(start 331.440536 -264.07618)
		(end 330.724256 -264.07618)
		(width 0.088646)
		(layer "In4.Cu")
		(net "M_B_CPU0_SA_DQ<27>")
	)
	(segment
		(start 304.403506 -282.986734)
		(end 304.403506 -283.411422)
		(width 0.18288)
		(layer "In4.Cu")
		(net "M_B_CPU0_SA_DQ<27>")
	)
	(segment
		(start 312.99277 -278.227282)
		(end 312.99277 -278.561038)
		(width 0.18288)
		(layer "In4.Cu")
		(net "M_B_CPU0_SA_DQ<27>")
	)
	(segment
		(start 306.041806 -282.798012)
		(end 305.858926 -282.615132)
		(width 0.18288)
		(layer "In4.Cu")
		(net "M_B_CPU0_SA_DQ<27>")
	)
	(segment
		(start 305.350926 -282.095448)
		(end 305.168046 -282.278328)
		(width 0.18288)
		(layer "In4.Cu")
		(net "M_B_CPU0_SA_DQ<27>")
	)
	(segment
		(start 303.74463 -283.671518)
		(end 303.022254 -284.393894)
		(width 0.18288)
		(layer "In4.Cu")
		(net "M_B_CPU0_SA_DQ<27>")
	)
	(segment
		(start 305.676046 -282.095448)
		(end 305.350926 -282.095448)
		(width 0.18288)
		(layer "In4.Cu")
		(net "M_B_CPU0_SA_DQ<27>")
	)
	(segment
		(start 307.429916 -282.055316)
		(end 306.68722 -282.798012)
		(width 0.18288)
		(layer "In4.Cu")
		(net "M_B_CPU0_SA_DQ<27>")
	)
	(segment
		(start 311.08523 -279.270206)
		(end 310.85917 -279.270206)
		(width 0.18288)
		(layer "In4.Cu")
		(net "M_B_CPU0_SA_DQ<27>")
	)
	(segment
		(start 300.172882 -285.286958)
		(end 299.782738 -285.448756)
		(width 0.18288)
		(layer "In4.Cu")
		(net "M_B_CPU0_SA_DQ<27>")
	)
	(segment
		(start 300.86681 -285.286958)
		(end 300.172882 -285.286958)
		(width 0.18288)
		(layer "In4.Cu")
		(net "M_B_CPU0_SA_DQ<27>")
	)
	(segment
		(start 307.890164 -282.055316)
		(end 307.429916 -282.055316)
		(width 0.18288)
		(layer "In4.Cu")
		(net "M_B_CPU0_SA_DQ<27>")
	)
	(segment
		(start 310.594756 -279.76068)
		(end 310.879998 -280.045922)
		(width 0.18288)
		(layer "In4.Cu")
		(net "M_B_CPU0_SA_DQ<27>")
	)
	(segment
		(start 310.64454 -280.50744)
		(end 309.922672 -280.50744)
		(width 0.18288)
		(layer "In4.Cu")
		(net "M_B_CPU0_SA_DQ<27>")
	)
	(segment
		(start 309.433976 -281.254708)
		(end 309.183532 -281.505152)
		(width 0.18288)
		(layer "In4.Cu")
		(net "M_B_CPU0_SA_DQ<27>")
	)
	(segment
		(start 337.891882 -264.013442)
		(end 337.887564 -264.010902)
		(width 0.088646)
		(layer "In4.Cu")
		(net "M_B_CPU0_SA_DQ<27>")
	)
	(arc
		(start 336.38236 -264.010902)
		(mid 336.195162 -264.061045)
		(end 336.007964 -264.010902)
		(width 0.088646)
		(layer "In4.Cu")
		(net "M_B_CPU0_SA_DQ<27>")
	)
	(arc
		(start 334.50276 -264.010902)
		(mid 334.315562 -264.061045)
		(end 334.128364 -264.010902)
		(width 0.088646)
		(layer "In4.Cu")
		(net "M_B_CPU0_SA_DQ<27>")
	)
	(arc
		(start 332.62316 -264.010902)
		(mid 332.435962 -264.061045)
		(end 332.248764 -264.010902)
		(width 0.088646)
		(layer "In4.Cu")
		(net "M_B_CPU0_SA_DQ<27>")
	)
	(arc
		(start 332.248764 -264.010902)
		(mid 331.966062 -263.935126)
		(end 331.68336 -264.010902)
		(width 0.088646)
		(layer "In4.Cu")
		(net "M_B_CPU0_SA_DQ<27>")
	)
	(arc
		(start 341.076026 -263.359138)
		(mid 340.958334 -263.311598)
		(end 340.83244 -263.295384)
		(width 0.088646)
		(layer "In4.Cu")
		(net "M_B_CPU0_SA_DQ<27>")
	)
	(arc
		(start 335.44256 -264.010902)
		(mid 335.255362 -264.061045)
		(end 335.068164 -264.010902)
		(width 0.088646)
		(layer "In4.Cu")
		(net "M_B_CPU0_SA_DQ<27>")
	)
	(arc
		(start 341.834216 -263.686544)
		(mid 341.648946 -263.662124)
		(end 341.47633 -263.590532)
		(width 0.088646)
		(layer "In4.Cu")
		(net "M_B_CPU0_SA_DQ<27>")
	)
	(arc
		(start 336.947764 -264.010902)
		(mid 336.665062 -263.935126)
		(end 336.38236 -264.010902)
		(width 0.088646)
		(layer "In4.Cu")
		(net "M_B_CPU0_SA_DQ<27>")
	)
	(arc
		(start 338.262214 -264.010902)
		(mid 338.077377 -264.061163)
		(end 337.891882 -264.013442)
		(width 0.088646)
		(layer "In4.Cu")
		(net "M_B_CPU0_SA_DQ<27>")
	)
	(arc
		(start 335.068164 -264.010902)
		(mid 334.785462 -263.935126)
		(end 334.50276 -264.010902)
		(width 0.088646)
		(layer "In4.Cu")
		(net "M_B_CPU0_SA_DQ<27>")
	)
	(arc
		(start 337.887564 -264.010902)
		(mid 337.605006 -263.935253)
		(end 337.322414 -264.010902)
		(width 0.088646)
		(layer "In4.Cu")
		(net "M_B_CPU0_SA_DQ<27>")
	)
	(arc
		(start 333.188564 -264.010902)
		(mid 332.905862 -263.935126)
		(end 332.62316 -264.010902)
		(width 0.088646)
		(layer "In4.Cu")
		(net "M_B_CPU0_SA_DQ<27>")
	)
	(arc
		(start 339.682582 -263.424924)
		(mid 339.679317 -263.42827)
		(end 339.676232 -263.431782)
		(width 0.088646)
		(layer "In4.Cu")
		(net "M_B_CPU0_SA_DQ<27>")
	)
	(arc
		(start 337.322414 -264.010902)
		(mid 337.138206 -264.061158)
		(end 336.953098 -264.014204)
		(width 0.088646)
		(layer "In4.Cu")
		(net "M_B_CPU0_SA_DQ<27>")
	)
	(arc
		(start 339.528658 -263.663176)
		(mid 339.458196 -263.787019)
		(end 339.363304 -263.8933)
		(width 0.088646)
		(layer "In4.Cu")
		(net "M_B_CPU0_SA_DQ<27>")
	)
	(arc
		(start 339.761322 -263.365488)
		(mid 339.720096 -263.392747)
		(end 339.682582 -263.424924)
		(width 0.088646)
		(layer "In4.Cu")
		(net "M_B_CPU0_SA_DQ<27>")
	)
	(arc
		(start 339.202014 -264.010902)
		(mid 339.01806 -264.061031)
		(end 338.833206 -264.014204)
		(width 0.088646)
		(layer "In4.Cu")
		(net "M_B_CPU0_SA_DQ<27>")
	)
	(arc
		(start 341.085424 -263.364472)
		(mid 341.080745 -263.361771)
		(end 341.076026 -263.359138)
		(width 0.088646)
		(layer "In4.Cu")
		(net "M_B_CPU0_SA_DQ<27>")
	)
	(arc
		(start 333.56296 -264.010902)
		(mid 333.375762 -264.061045)
		(end 333.188564 -264.010902)
		(width 0.088646)
		(layer "In4.Cu")
		(net "M_B_CPU0_SA_DQ<27>")
	)
	(arc
		(start 339.569044 -263.583928)
		(mid 339.547654 -263.622942)
		(end 339.528658 -263.663176)
		(width 0.088646)
		(layer "In4.Cu")
		(net "M_B_CPU0_SA_DQ<27>")
	)
	(arc
		(start 339.363304 -263.8933)
		(mid 339.285785 -263.956387)
		(end 339.202014 -264.010902)
		(width 0.088646)
		(layer "In4.Cu")
		(net "M_B_CPU0_SA_DQ<27>")
	)
	(arc
		(start 340.017354 -263.295384)
		(mid 339.891145 -263.311436)
		(end 339.773006 -263.35863)
		(width 0.088646)
		(layer "In4.Cu")
		(net "M_B_CPU0_SA_DQ<27>")
	)
	(arc
		(start 338.821522 -264.007346)
		(mid 338.541387 -263.935063)
		(end 338.262214 -264.010902)
		(width 0.088646)
		(layer "In4.Cu")
		(net "M_B_CPU0_SA_DQ<27>")
	)
	(arc
		(start 336.007964 -264.010902)
		(mid 335.725262 -263.935126)
		(end 335.44256 -264.010902)
		(width 0.088646)
		(layer "In4.Cu")
		(net "M_B_CPU0_SA_DQ<27>")
	)
	(arc
		(start 331.68336 -264.010902)
		(mid 331.566266 -264.059616)
		(end 331.440536 -264.07618)
		(width 0.088646)
		(layer "In4.Cu")
		(net "M_B_CPU0_SA_DQ<27>")
	)
	(arc
		(start 339.676232 -263.431782)
		(mid 339.6196 -263.505715)
		(end 339.569044 -263.583928)
		(width 0.088646)
		(layer "In4.Cu")
		(net "M_B_CPU0_SA_DQ<27>")
	)
	(arc
		(start 334.128364 -264.010902)
		(mid 333.845662 -263.935126)
		(end 333.56296 -264.010902)
		(width 0.088646)
		(layer "In4.Cu")
		(net "M_B_CPU0_SA_DQ<27>")
	)
	(segment
		(start 296.584878 -287.416748)
		(end 296.373042 -287.628584)
		(width 0.20066)
		(layer "F.Cu")
		(net "M_B_CPU0_SA_DQ<26>")
	)
	(segment
		(start 292.940486 -286.991806)
		(end 292.68547 -286.991806)
		(width 0.101854)
		(layer "F.Cu")
		(net "M_B_CPU0_SA_DQ<26>")
	)
	(segment
		(start 297.899582 -287.416748)
		(end 296.584878 -287.416748)
		(width 0.20066)
		(layer "F.Cu")
		(net "M_B_CPU0_SA_DQ<26>")
	)
	(segment
		(start 295.000426 -286.991806)
		(end 292.940486 -286.991806)
		(width 0.1016)
		(layer "F.Cu")
		(net "M_B_CPU0_SA_DQ<26>")
	)
	(segment
		(start 295.633394 -286.991806)
		(end 295.000426 -286.991806)
		(width 0.20066)
		(layer "F.Cu")
		(net "M_B_CPU0_SA_DQ<26>")
	)
	(segment
		(start 292.68547 -286.991806)
		(end 292.67531 -286.981646)
		(width 0.101854)
		(layer "F.Cu")
		(net "M_B_CPU0_SA_DQ<26>")
	)
	(segment
		(start 341.364316 -263.96442)
		(end 341.364062 -263.964674)
		(width 0.20066)
		(layer "F.Cu")
		(net "M_B_CPU0_SA_DQ<26>")
	)
	(segment
		(start 292.67531 -286.981646)
		(end 291.937948 -286.981646)
		(width 0.20066)
		(layer "F.Cu")
		(net "M_B_CPU0_SA_DQ<26>")
	)
	(segment
		(start 299.004482 -287.416748)
		(end 297.899582 -287.416748)
		(width 0.20066)
		(layer "F.Cu")
		(net "M_B_CPU0_SA_DQ<26>")
	)
	(segment
		(start 296.373042 -287.628584)
		(end 295.944544 -287.628584)
		(width 0.20066)
		(layer "F.Cu")
		(net "M_B_CPU0_SA_DQ<26>")
	)
	(segment
		(start 291.937948 -286.981646)
		(end 291.502846 -287.416748)
		(width 0.20066)
		(layer "F.Cu")
		(net "M_B_CPU0_SA_DQ<26>")
	)
	(segment
		(start 291.502846 -287.416748)
		(end 290.355782 -287.416748)
		(width 0.20066)
		(layer "F.Cu")
		(net "M_B_CPU0_SA_DQ<26>")
	)
	(segment
		(start 341.364062 -263.964674)
		(end 341.364062 -264.50036)
		(width 0.20066)
		(layer "F.Cu")
		(net "M_B_CPU0_SA_DQ<26>")
	)
	(segment
		(start 295.777158 -287.13557)
		(end 295.633394 -286.991806)
		(width 0.20066)
		(layer "F.Cu")
		(net "M_B_CPU0_SA_DQ<26>")
	)
	(segment
		(start 295.944544 -287.628584)
		(end 295.777158 -287.461198)
		(width 0.20066)
		(layer "F.Cu")
		(net "M_B_CPU0_SA_DQ<26>")
	)
	(segment
		(start 295.777158 -287.461198)
		(end 295.777158 -287.13557)
		(width 0.20066)
		(layer "F.Cu")
		(net "M_B_CPU0_SA_DQ<26>")
	)
	(segment
		(start 311.458864 -282.771596)
		(end 309.979568 -284.250892)
		(width 0.18288)
		(layer "In4.Cu")
		(net "M_B_CPU0_SA_DQ<26>")
	)
	(segment
		(start 302.141636 -286.930084)
		(end 301.965868 -287.105852)
		(width 0.18288)
		(layer "In4.Cu")
		(net "M_B_CPU0_SA_DQ<26>")
	)
	(segment
		(start 309.471568 -284.090872)
		(end 309.471568 -283.762196)
		(width 0.18288)
		(layer "In4.Cu")
		(net "M_B_CPU0_SA_DQ<26>")
	)
	(segment
		(start 309.979568 -284.250892)
		(end 309.631588 -284.250892)
		(width 0.18288)
		(layer "In4.Cu")
		(net "M_B_CPU0_SA_DQ<26>")
	)
	(segment
		(start 330.931774 -265.5697)
		(end 330.724256 -265.5697)
		(width 0.088646)
		(layer "In4.Cu")
		(net "M_B_CPU0_SA_DQ<26>")
	)
	(segment
		(start 309.311548 -283.602176)
		(end 308.831488 -283.602176)
		(width 0.18288)
		(layer "In4.Cu")
		(net "M_B_CPU0_SA_DQ<26>")
	)
	(segment
		(start 307.268626 -285.12008)
		(end 307.085746 -284.9372)
		(width 0.18288)
		(layer "In4.Cu")
		(net "M_B_CPU0_SA_DQ<26>")
	)
	(segment
		(start 340.78545 -264.944606)
		(end 340.707218 -264.989818)
		(width 0.088646)
		(layer "In4.Cu")
		(net "M_B_CPU0_SA_DQ<26>")
	)
	(segment
		(start 307.956204 -284.386274)
		(end 307.796184 -284.546294)
		(width 0.18288)
		(layer "In4.Cu")
		(net "M_B_CPU0_SA_DQ<26>")
	)
	(segment
		(start 302.885094 -286.930084)
		(end 302.141636 -286.930084)
		(width 0.18288)
		(layer "In4.Cu")
		(net "M_B_CPU0_SA_DQ<26>")
	)
	(segment
		(start 303.599088 -285.981394)
		(end 303.341278 -286.239204)
		(width 0.18288)
		(layer "In4.Cu")
		(net "M_B_CPU0_SA_DQ<26>")
	)
	(segment
		(start 299.634402 -287.416748)
		(end 299.004482 -287.416748)
		(width 0.18288)
		(layer "In4.Cu")
		(net "M_B_CPU0_SA_DQ<26>")
	)
	(segment
		(start 312.828178 -282.029662)
		(end 312.828178 -282.255722)
		(width 0.18288)
		(layer "In4.Cu")
		(net "M_B_CPU0_SA_DQ<26>")
	)
	(segment
		(start 312.828178 -282.255722)
		(end 312.312304 -282.771596)
		(width 0.18288)
		(layer "In4.Cu")
		(net "M_B_CPU0_SA_DQ<26>")
	)
	(segment
		(start 308.638448 -283.795216)
		(end 308.638448 -284.23108)
		(width 0.18288)
		(layer "In4.Cu")
		(net "M_B_CPU0_SA_DQ<26>")
	)
	(segment
		(start 309.631588 -284.250892)
		(end 309.471568 -284.090872)
		(width 0.18288)
		(layer "In4.Cu")
		(net "M_B_CPU0_SA_DQ<26>")
	)
	(segment
		(start 307.085746 -284.9372)
		(end 307.085746 -284.546294)
		(width 0.18288)
		(layer "In4.Cu")
		(net "M_B_CPU0_SA_DQ<26>")
	)
	(segment
		(start 307.085746 -284.546294)
		(end 306.925726 -284.386274)
		(width 0.18288)
		(layer "In4.Cu")
		(net "M_B_CPU0_SA_DQ<26>")
	)
	(segment
		(start 306.925726 -284.386274)
		(end 306.191158 -284.386274)
		(width 0.18288)
		(layer "In4.Cu")
		(net "M_B_CPU0_SA_DQ<26>")
	)
	(segment
		(start 327.563734 -265.912346)
		(end 315.813948 -277.662132)
		(width 0.18288)
		(layer "In4.Cu")
		(net "M_B_CPU0_SA_DQ<26>")
	)
	(segment
		(start 328.390504 -265.5697)
		(end 327.563734 -265.912346)
		(width 0.18288)
		(layer "In4.Cu")
		(net "M_B_CPU0_SA_DQ<26>")
	)
	(segment
		(start 314.223146 -281.116278)
		(end 313.34329 -281.116278)
		(width 0.18288)
		(layer "In4.Cu")
		(net "M_B_CPU0_SA_DQ<26>")
	)
	(segment
		(start 338.272374 -264.995914)
		(end 338.26196 -264.989818)
		(width 0.088646)
		(layer "In4.Cu")
		(net "M_B_CPU0_SA_DQ<26>")
	)
	(segment
		(start 301.965868 -287.105852)
		(end 300.546008 -287.105852)
		(width 0.18288)
		(layer "In4.Cu")
		(net "M_B_CPU0_SA_DQ<26>")
	)
	(segment
		(start 308.638448 -284.23108)
		(end 308.483254 -284.386274)
		(width 0.18288)
		(layer "In4.Cu")
		(net "M_B_CPU0_SA_DQ<26>")
	)
	(segment
		(start 303.341278 -286.4739)
		(end 302.885094 -286.930084)
		(width 0.18288)
		(layer "In4.Cu")
		(net "M_B_CPU0_SA_DQ<26>")
	)
	(segment
		(start 300.431708 -286.991552)
		(end 300.059598 -286.991552)
		(width 0.18288)
		(layer "In4.Cu")
		(net "M_B_CPU0_SA_DQ<26>")
	)
	(segment
		(start 312.312304 -282.771596)
		(end 311.458864 -282.771596)
		(width 0.18288)
		(layer "In4.Cu")
		(net "M_B_CPU0_SA_DQ<26>")
	)
	(segment
		(start 340.151974 -264.995914)
		(end 340.14156 -264.989818)
		(width 0.088646)
		(layer "In4.Cu")
		(net "M_B_CPU0_SA_DQ<26>")
	)
	(segment
		(start 330.724256 -265.5697)
		(end 328.390504 -265.5697)
		(width 0.18288)
		(layer "In4.Cu")
		(net "M_B_CPU0_SA_DQ<26>")
	)
	(segment
		(start 307.796184 -284.9372)
		(end 307.613304 -285.12008)
		(width 0.18288)
		(layer "In4.Cu")
		(net "M_B_CPU0_SA_DQ<26>")
	)
	(segment
		(start 315.813948 -277.662132)
		(end 314.496196 -280.843228)
		(width 0.18288)
		(layer "In4.Cu")
		(net "M_B_CPU0_SA_DQ<26>")
	)
	(segment
		(start 312.742072 -281.717496)
		(end 312.742072 -281.943556)
		(width 0.18288)
		(layer "In4.Cu")
		(net "M_B_CPU0_SA_DQ<26>")
	)
	(segment
		(start 308.831488 -283.602176)
		(end 308.638448 -283.795216)
		(width 0.18288)
		(layer "In4.Cu")
		(net "M_B_CPU0_SA_DQ<26>")
	)
	(segment
		(start 307.613304 -285.12008)
		(end 307.268626 -285.12008)
		(width 0.18288)
		(layer "In4.Cu")
		(net "M_B_CPU0_SA_DQ<26>")
	)
	(segment
		(start 339.767164 -264.989818)
		(end 339.75675 -264.995914)
		(width 0.088646)
		(layer "In4.Cu")
		(net "M_B_CPU0_SA_DQ<26>")
	)
	(segment
		(start 303.341278 -286.239204)
		(end 303.341278 -286.4739)
		(width 0.18288)
		(layer "In4.Cu")
		(net "M_B_CPU0_SA_DQ<26>")
	)
	(segment
		(start 331.433932 -265.067542)
		(end 330.931774 -265.5697)
		(width 0.088646)
		(layer "In4.Cu")
		(net "M_B_CPU0_SA_DQ<26>")
	)
	(segment
		(start 309.471568 -283.762196)
		(end 309.311548 -283.602176)
		(width 0.18288)
		(layer "In4.Cu")
		(net "M_B_CPU0_SA_DQ<26>")
	)
	(segment
		(start 308.483254 -284.386274)
		(end 307.956204 -284.386274)
		(width 0.18288)
		(layer "In4.Cu")
		(net "M_B_CPU0_SA_DQ<26>")
	)
	(segment
		(start 304.596038 -285.981394)
		(end 303.599088 -285.981394)
		(width 0.18288)
		(layer "In4.Cu")
		(net "M_B_CPU0_SA_DQ<26>")
	)
	(segment
		(start 306.191158 -284.386274)
		(end 304.596038 -285.981394)
		(width 0.18288)
		(layer "In4.Cu")
		(net "M_B_CPU0_SA_DQ<26>")
	)
	(segment
		(start 313.34329 -281.116278)
		(end 312.742072 -281.717496)
		(width 0.18288)
		(layer "In4.Cu")
		(net "M_B_CPU0_SA_DQ<26>")
	)
	(segment
		(start 300.546008 -287.105852)
		(end 300.431708 -286.991552)
		(width 0.18288)
		(layer "In4.Cu")
		(net "M_B_CPU0_SA_DQ<26>")
	)
	(segment
		(start 314.496196 -280.843228)
		(end 314.223146 -281.116278)
		(width 0.18288)
		(layer "In4.Cu")
		(net "M_B_CPU0_SA_DQ<26>")
	)
	(segment
		(start 307.796184 -284.546294)
		(end 307.796184 -284.9372)
		(width 0.18288)
		(layer "In4.Cu")
		(net "M_B_CPU0_SA_DQ<26>")
	)
	(segment
		(start 312.742072 -281.943556)
		(end 312.828178 -282.029662)
		(width 0.18288)
		(layer "In4.Cu")
		(net "M_B_CPU0_SA_DQ<26>")
	)
	(segment
		(start 300.059598 -286.991552)
		(end 299.634402 -287.416748)
		(width 0.18288)
		(layer "In4.Cu")
		(net "M_B_CPU0_SA_DQ<26>")
	)
	(arc
		(start 338.26196 -264.989818)
		(mid 338.074762 -264.939675)
		(end 337.887564 -264.989818)
		(width 0.088646)
		(layer "In4.Cu")
		(net "M_B_CPU0_SA_DQ<26>")
	)
	(arc
		(start 337.887564 -264.989818)
		(mid 337.604862 -265.065594)
		(end 337.32216 -264.989818)
		(width 0.088646)
		(layer "In4.Cu")
		(net "M_B_CPU0_SA_DQ<26>")
	)
	(arc
		(start 334.128364 -264.989818)
		(mid 333.845662 -265.065594)
		(end 333.56296 -264.989818)
		(width 0.088646)
		(layer "In4.Cu")
		(net "M_B_CPU0_SA_DQ<26>")
	)
	(arc
		(start 331.618336 -264.991088)
		(mid 331.518539 -265.010975)
		(end 331.433932 -265.067542)
		(width 0.088646)
		(layer "In4.Cu")
		(net "M_B_CPU0_SA_DQ<26>")
	)
	(arc
		(start 338.827618 -264.989818)
		(mid 338.550805 -265.065688)
		(end 338.272374 -264.995914)
		(width 0.088646)
		(layer "In4.Cu")
		(net "M_B_CPU0_SA_DQ<26>")
	)
	(arc
		(start 332.248764 -264.989818)
		(mid 331.994607 -265.064987)
		(end 331.73416 -265.01598)
		(width 0.088646)
		(layer "In4.Cu")
		(net "M_B_CPU0_SA_DQ<26>")
	)
	(arc
		(start 336.947764 -264.989818)
		(mid 336.665062 -265.065594)
		(end 336.38236 -264.989818)
		(width 0.088646)
		(layer "In4.Cu")
		(net "M_B_CPU0_SA_DQ<26>")
	)
	(arc
		(start 337.32216 -264.989818)
		(mid 337.134962 -264.939675)
		(end 336.947764 -264.989818)
		(width 0.088646)
		(layer "In4.Cu")
		(net "M_B_CPU0_SA_DQ<26>")
	)
	(arc
		(start 333.56296 -264.989818)
		(mid 333.375762 -264.939675)
		(end 333.188564 -264.989818)
		(width 0.088646)
		(layer "In4.Cu")
		(net "M_B_CPU0_SA_DQ<26>")
	)
	(arc
		(start 336.007964 -264.989818)
		(mid 335.725262 -265.065594)
		(end 335.44256 -264.989818)
		(width 0.088646)
		(layer "In4.Cu")
		(net "M_B_CPU0_SA_DQ<26>")
	)
	(arc
		(start 336.38236 -264.989818)
		(mid 336.195162 -264.939675)
		(end 336.007964 -264.989818)
		(width 0.088646)
		(layer "In4.Cu")
		(net "M_B_CPU0_SA_DQ<26>")
	)
	(arc
		(start 341.364062 -264.50036)
		(mid 341.089281 -264.741401)
		(end 340.78545 -264.944606)
		(width 0.088646)
		(layer "In4.Cu")
		(net "M_B_CPU0_SA_DQ<26>")
	)
	(arc
		(start 335.44256 -264.989818)
		(mid 335.255362 -264.939675)
		(end 335.068164 -264.989818)
		(width 0.088646)
		(layer "In4.Cu")
		(net "M_B_CPU0_SA_DQ<26>")
	)
	(arc
		(start 340.14156 -264.989818)
		(mid 339.954362 -264.939675)
		(end 339.767164 -264.989818)
		(width 0.088646)
		(layer "In4.Cu")
		(net "M_B_CPU0_SA_DQ<26>")
	)
	(arc
		(start 333.188564 -264.989818)
		(mid 332.905862 -265.065594)
		(end 332.62316 -264.989818)
		(width 0.088646)
		(layer "In4.Cu")
		(net "M_B_CPU0_SA_DQ<26>")
	)
	(arc
		(start 334.50276 -264.989818)
		(mid 334.315562 -264.939675)
		(end 334.128364 -264.989818)
		(width 0.088646)
		(layer "In4.Cu")
		(net "M_B_CPU0_SA_DQ<26>")
	)
	(arc
		(start 339.202014 -264.989818)
		(mid 339.014816 -264.939675)
		(end 338.827618 -264.989818)
		(width 0.088646)
		(layer "In4.Cu")
		(net "M_B_CPU0_SA_DQ<26>")
	)
	(arc
		(start 332.62316 -264.989818)
		(mid 332.435962 -264.939675)
		(end 332.248764 -264.989818)
		(width 0.088646)
		(layer "In4.Cu")
		(net "M_B_CPU0_SA_DQ<26>")
	)
	(arc
		(start 340.707218 -264.989818)
		(mid 340.430405 -265.065688)
		(end 340.151974 -264.995914)
		(width 0.088646)
		(layer "In4.Cu")
		(net "M_B_CPU0_SA_DQ<26>")
	)
	(arc
		(start 335.068164 -264.989818)
		(mid 334.785462 -265.065594)
		(end 334.50276 -264.989818)
		(width 0.088646)
		(layer "In4.Cu")
		(net "M_B_CPU0_SA_DQ<26>")
	)
	(arc
		(start 339.75675 -264.995914)
		(mid 339.478572 -265.065637)
		(end 339.202014 -264.989818)
		(width 0.088646)
		(layer "In4.Cu")
		(net "M_B_CPU0_SA_DQ<26>")
	)
	(arc
		(start 331.73416 -265.01598)
		(mid 331.677571 -264.997365)
		(end 331.618336 -264.991088)
		(width 0.088646)
		(layer "In4.Cu")
		(net "M_B_CPU0_SA_DQ<26>")
	)
	(segment
		(start 293.799514 -286.56661)
		(end 292.160198 -286.56661)
		(width 0.20066)
		(layer "F.Cu")
		(net "M_B_CPU0_SA_DQ<25>")
	)
	(segment
		(start 291.735256 -286.141668)
		(end 291.556694 -286.141668)
		(width 0.20066)
		(layer "F.Cu")
		(net "M_B_CPU0_SA_DQ<25>")
	)
	(segment
		(start 289.231578 -286.132778)
		(end 288.62274 -286.132778)
		(width 0.20066)
		(layer "F.Cu")
		(net "M_B_CPU0_SA_DQ<25>")
	)
	(segment
		(start 288.62274 -286.132778)
		(end 288.46018 -286.295338)
		(width 0.20066)
		(layer "F.Cu")
		(net "M_B_CPU0_SA_DQ<25>")
	)
	(segment
		(start 288.46018 -286.295338)
		(end 288.46018 -286.623506)
		(width 0.20066)
		(layer "F.Cu")
		(net "M_B_CPU0_SA_DQ<25>")
	)
	(segment
		(start 292.160198 -286.56661)
		(end 291.735256 -286.141668)
		(width 0.20066)
		(layer "F.Cu")
		(net "M_B_CPU0_SA_DQ<25>")
	)
	(segment
		(start 291.225986 -286.141668)
		(end 289.240468 -286.141668)
		(width 0.1016)
		(layer "F.Cu")
		(net "M_B_CPU0_SA_DQ<25>")
	)
	(segment
		(start 287.589976 -286.56661)
		(end 286.255714 -286.56661)
		(width 0.20066)
		(layer "F.Cu")
		(net "M_B_CPU0_SA_DQ<25>")
	)
	(segment
		(start 291.556694 -286.141668)
		(end 291.225986 -286.141668)
		(width 0.101854)
		(layer "F.Cu")
		(net "M_B_CPU0_SA_DQ<25>")
	)
	(segment
		(start 339.954362 -263.150604)
		(end 339.954362 -263.68629)
		(width 0.20066)
		(layer "F.Cu")
		(net "M_B_CPU0_SA_DQ<25>")
	)
	(segment
		(start 287.801304 -286.777938)
		(end 287.589976 -286.56661)
		(width 0.20066)
		(layer "F.Cu")
		(net "M_B_CPU0_SA_DQ<25>")
	)
	(segment
		(start 294.904414 -286.56661)
		(end 293.799514 -286.56661)
		(width 0.20066)
		(layer "F.Cu")
		(net "M_B_CPU0_SA_DQ<25>")
	)
	(segment
		(start 289.240468 -286.141668)
		(end 289.231578 -286.132778)
		(width 0.1016)
		(layer "F.Cu")
		(net "M_B_CPU0_SA_DQ<25>")
	)
	(segment
		(start 288.305748 -286.777938)
		(end 287.801304 -286.777938)
		(width 0.20066)
		(layer "F.Cu")
		(net "M_B_CPU0_SA_DQ<25>")
	)
	(segment
		(start 339.954362 -263.68629)
		(end 339.954616 -263.686544)
		(width 0.20066)
		(layer "F.Cu")
		(net "M_B_CPU0_SA_DQ<25>")
	)
	(segment
		(start 288.46018 -286.623506)
		(end 288.305748 -286.777938)
		(width 0.20066)
		(layer "F.Cu")
		(net "M_B_CPU0_SA_DQ<25>")
	)
	(segment
		(start 305.745134 -283.354526)
		(end 304.76698 -284.33268)
		(width 0.18288)
		(layer "In4.Cu")
		(net "M_B_CPU0_SA_DQ<25>")
	)
	(segment
		(start 328.147172 -264.57402)
		(end 326.91197 -265.085322)
		(width 0.18288)
		(layer "In4.Cu")
		(net "M_B_CPU0_SA_DQ<25>")
	)
	(segment
		(start 296.66057 -285.37789)
		(end 296.47769 -285.56077)
		(width 0.18288)
		(layer "In4.Cu")
		(net "M_B_CPU0_SA_DQ<25>")
	)
	(segment
		(start 308.669436 -282.071826)
		(end 308.059582 -282.68168)
		(width 0.18288)
		(layer "In4.Cu")
		(net "M_B_CPU0_SA_DQ<25>")
	)
	(segment
		(start 304.484278 -284.33268)
		(end 300.677834 -285.909512)
		(width 0.18288)
		(layer "In4.Cu")
		(net "M_B_CPU0_SA_DQ<25>")
	)
	(segment
		(start 297.16857 -285.958788)
		(end 297.16857 -285.56077)
		(width 0.18288)
		(layer "In4.Cu")
		(net "M_B_CPU0_SA_DQ<25>")
	)
	(segment
		(start 312.568844 -280.015696)
		(end 311.855612 -280.015696)
		(width 0.18288)
		(layer "In4.Cu")
		(net "M_B_CPU0_SA_DQ<25>")
	)
	(segment
		(start 331.778864 -264.176002)
		(end 331.15631 -264.535412)
		(width 0.088646)
		(layer "In4.Cu")
		(net "M_B_CPU0_SA_DQ<25>")
	)
	(segment
		(start 297.35145 -286.141668)
		(end 297.16857 -285.958788)
		(width 0.18288)
		(layer "In4.Cu")
		(net "M_B_CPU0_SA_DQ<25>")
	)
	(segment
		(start 330.724256 -264.57402)
		(end 328.147172 -264.57402)
		(width 0.18288)
		(layer "In4.Cu")
		(net "M_B_CPU0_SA_DQ<25>")
	)
	(segment
		(start 310.720994 -281.150314)
		(end 310.720994 -281.514042)
		(width 0.18288)
		(layer "In4.Cu")
		(net "M_B_CPU0_SA_DQ<25>")
	)
	(segment
		(start 310.720994 -281.514042)
		(end 310.16321 -282.071826)
		(width 0.18288)
		(layer "In4.Cu")
		(net "M_B_CPU0_SA_DQ<25>")
	)
	(segment
		(start 337.79587 -264.178034)
		(end 337.792314 -264.175748)
		(width 0.088646)
		(layer "In4.Cu")
		(net "M_B_CPU0_SA_DQ<25>")
	)
	(segment
		(start 304.76698 -284.33268)
		(end 304.484278 -284.33268)
		(width 0.18288)
		(layer "In4.Cu")
		(net "M_B_CPU0_SA_DQ<25>")
	)
	(segment
		(start 326.91197 -265.085322)
		(end 313.504326 -278.492966)
		(width 0.18288)
		(layer "In4.Cu")
		(net "M_B_CPU0_SA_DQ<25>")
	)
	(segment
		(start 296.29481 -286.141668)
		(end 295.329356 -286.141668)
		(width 0.18288)
		(layer "In4.Cu")
		(net "M_B_CPU0_SA_DQ<25>")
	)
	(segment
		(start 306.865528 -283.354526)
		(end 305.745134 -283.354526)
		(width 0.18288)
		(layer "In4.Cu")
		(net "M_B_CPU0_SA_DQ<25>")
	)
	(segment
		(start 307.538374 -282.68168)
		(end 306.865528 -283.354526)
		(width 0.18288)
		(layer "In4.Cu")
		(net "M_B_CPU0_SA_DQ<25>")
	)
	(segment
		(start 338.732114 -264.175748)
		(end 338.726272 -264.172446)
		(width 0.088646)
		(layer "In4.Cu")
		(net "M_B_CPU0_SA_DQ<25>")
	)
	(segment
		(start 295.329356 -286.141668)
		(end 294.904414 -286.56661)
		(width 0.18288)
		(layer "In4.Cu")
		(net "M_B_CPU0_SA_DQ<25>")
	)
	(segment
		(start 296.47769 -285.56077)
		(end 296.47769 -285.958788)
		(width 0.18288)
		(layer "In4.Cu")
		(net "M_B_CPU0_SA_DQ<25>")
	)
	(segment
		(start 336.857086 -264.178542)
		(end 336.85226 -264.176002)
		(width 0.088646)
		(layer "In4.Cu")
		(net "M_B_CPU0_SA_DQ<25>")
	)
	(segment
		(start 313.504326 -278.492966)
		(end 313.504326 -279.080214)
		(width 0.18288)
		(layer "In4.Cu")
		(net "M_B_CPU0_SA_DQ<25>")
	)
	(segment
		(start 297.16857 -285.56077)
		(end 296.98569 -285.37789)
		(width 0.18288)
		(layer "In4.Cu")
		(net "M_B_CPU0_SA_DQ<25>")
	)
	(segment
		(start 300.677834 -285.909512)
		(end 300.445678 -286.141668)
		(width 0.18288)
		(layer "In4.Cu")
		(net "M_B_CPU0_SA_DQ<25>")
	)
	(segment
		(start 338.737956 -264.179304)
		(end 338.732114 -264.175748)
		(width 0.088646)
		(layer "In4.Cu")
		(net "M_B_CPU0_SA_DQ<25>")
	)
	(segment
		(start 300.445678 -286.141668)
		(end 297.35145 -286.141668)
		(width 0.18288)
		(layer "In4.Cu")
		(net "M_B_CPU0_SA_DQ<25>")
	)
	(segment
		(start 296.98569 -285.37789)
		(end 296.66057 -285.37789)
		(width 0.18288)
		(layer "In4.Cu")
		(net "M_B_CPU0_SA_DQ<25>")
	)
	(segment
		(start 296.47769 -285.958788)
		(end 296.29481 -286.141668)
		(width 0.18288)
		(layer "In4.Cu")
		(net "M_B_CPU0_SA_DQ<25>")
	)
	(segment
		(start 313.504326 -279.080214)
		(end 312.568844 -280.015696)
		(width 0.18288)
		(layer "In4.Cu")
		(net "M_B_CPU0_SA_DQ<25>")
	)
	(segment
		(start 339.377782 -264.129266)
		(end 339.297264 -264.175748)
		(width 0.088646)
		(layer "In4.Cu")
		(net "M_B_CPU0_SA_DQ<25>")
	)
	(segment
		(start 311.855612 -280.015696)
		(end 310.720994 -281.150314)
		(width 0.18288)
		(layer "In4.Cu")
		(net "M_B_CPU0_SA_DQ<25>")
	)
	(segment
		(start 331.011784 -264.57402)
		(end 330.724256 -264.57402)
		(width 0.088646)
		(layer "In4.Cu")
		(net "M_B_CPU0_SA_DQ<25>")
	)
	(segment
		(start 308.059582 -282.68168)
		(end 307.538374 -282.68168)
		(width 0.18288)
		(layer "In4.Cu")
		(net "M_B_CPU0_SA_DQ<25>")
	)
	(segment
		(start 310.16321 -282.071826)
		(end 308.669436 -282.071826)
		(width 0.18288)
		(layer "In4.Cu")
		(net "M_B_CPU0_SA_DQ<25>")
	)
	(arc
		(start 335.91246 -264.176002)
		(mid 335.725262 -264.125859)
		(end 335.538064 -264.176002)
		(width 0.088646)
		(layer "In4.Cu")
		(net "M_B_CPU0_SA_DQ<25>")
	)
	(arc
		(start 334.598264 -264.176002)
		(mid 334.315562 -264.251778)
		(end 334.03286 -264.176002)
		(width 0.088646)
		(layer "In4.Cu")
		(net "M_B_CPU0_SA_DQ<25>")
	)
	(arc
		(start 336.477864 -264.176002)
		(mid 336.195162 -264.251778)
		(end 335.91246 -264.176002)
		(width 0.088646)
		(layer "In4.Cu")
		(net "M_B_CPU0_SA_DQ<25>")
	)
	(arc
		(start 332.15326 -264.176002)
		(mid 331.966062 -264.125859)
		(end 331.778864 -264.176002)
		(width 0.088646)
		(layer "In4.Cu")
		(net "M_B_CPU0_SA_DQ<25>")
	)
	(arc
		(start 333.658464 -264.176002)
		(mid 333.375762 -264.251778)
		(end 333.09306 -264.176002)
		(width 0.088646)
		(layer "In4.Cu")
		(net "M_B_CPU0_SA_DQ<25>")
	)
	(arc
		(start 339.297264 -264.175748)
		(mid 339.01809 -264.251547)
		(end 338.737956 -264.179304)
		(width 0.088646)
		(layer "In4.Cu")
		(net "M_B_CPU0_SA_DQ<25>")
	)
	(arc
		(start 332.718664 -264.176002)
		(mid 332.435962 -264.251778)
		(end 332.15326 -264.176002)
		(width 0.088646)
		(layer "In4.Cu")
		(net "M_B_CPU0_SA_DQ<25>")
	)
	(arc
		(start 337.417664 -264.175748)
		(mid 337.13775 -264.251551)
		(end 336.857086 -264.178542)
		(width 0.088646)
		(layer "In4.Cu")
		(net "M_B_CPU0_SA_DQ<25>")
	)
	(arc
		(start 334.97266 -264.176002)
		(mid 334.785462 -264.125859)
		(end 334.598264 -264.176002)
		(width 0.088646)
		(layer "In4.Cu")
		(net "M_B_CPU0_SA_DQ<25>")
	)
	(arc
		(start 338.357464 -264.175748)
		(mid 338.076983 -264.25152)
		(end 337.79587 -264.178034)
		(width 0.088646)
		(layer "In4.Cu")
		(net "M_B_CPU0_SA_DQ<25>")
	)
	(arc
		(start 338.726272 -264.172446)
		(mid 338.541417 -264.125528)
		(end 338.357464 -264.175748)
		(width 0.088646)
		(layer "In4.Cu")
		(net "M_B_CPU0_SA_DQ<25>")
	)
	(arc
		(start 336.85226 -264.176002)
		(mid 336.665062 -264.125859)
		(end 336.477864 -264.176002)
		(width 0.088646)
		(layer "In4.Cu")
		(net "M_B_CPU0_SA_DQ<25>")
	)
	(arc
		(start 337.792314 -264.175748)
		(mid 337.605006 -264.125639)
		(end 337.417664 -264.175748)
		(width 0.088646)
		(layer "In4.Cu")
		(net "M_B_CPU0_SA_DQ<25>")
	)
	(arc
		(start 331.15631 -264.535412)
		(mid 331.086586 -264.564215)
		(end 331.011784 -264.57402)
		(width 0.088646)
		(layer "In4.Cu")
		(net "M_B_CPU0_SA_DQ<25>")
	)
	(arc
		(start 339.954616 -263.686544)
		(mid 339.680658 -263.926743)
		(end 339.377782 -264.129266)
		(width 0.088646)
		(layer "In4.Cu")
		(net "M_B_CPU0_SA_DQ<25>")
	)
	(arc
		(start 335.538064 -264.176002)
		(mid 335.255362 -264.251778)
		(end 334.97266 -264.176002)
		(width 0.088646)
		(layer "In4.Cu")
		(net "M_B_CPU0_SA_DQ<25>")
	)
	(arc
		(start 333.09306 -264.176002)
		(mid 332.905862 -264.125859)
		(end 332.718664 -264.176002)
		(width 0.088646)
		(layer "In4.Cu")
		(net "M_B_CPU0_SA_DQ<25>")
	)
	(arc
		(start 334.03286 -264.176002)
		(mid 333.845662 -264.125859)
		(end 333.658464 -264.176002)
		(width 0.088646)
		(layer "In4.Cu")
		(net "M_B_CPU0_SA_DQ<25>")
	)
	(segment
		(start 340.424262 -263.964674)
		(end 340.424262 -264.50036)
		(width 0.20066)
		(layer "F.Cu")
		(net "M_B_CPU0_SA_DQ<24>")
	)
	(segment
		(start 288.46018 -288.043112)
		(end 288.46018 -288.332672)
		(width 0.20066)
		(layer "F.Cu")
		(net "M_B_CPU0_SA_DQ<24>")
	)
	(segment
		(start 291.556694 -287.84169)
		(end 289.48761 -287.84169)
		(width 0.1016)
		(layer "F.Cu")
		(net "M_B_CPU0_SA_DQ<24>")
	)
	(segment
		(start 288.66973 -287.833562)
		(end 288.46018 -288.043112)
		(width 0.20066)
		(layer "F.Cu")
		(net "M_B_CPU0_SA_DQ<24>")
	)
	(segment
		(start 288.46018 -288.332672)
		(end 288.28746 -288.505392)
		(width 0.20066)
		(layer "F.Cu")
		(net "M_B_CPU0_SA_DQ<24>")
	)
	(segment
		(start 287.589976 -288.266632)
		(end 286.255714 -288.266632)
		(width 0.20066)
		(layer "F.Cu")
		(net "M_B_CPU0_SA_DQ<24>")
	)
	(segment
		(start 292.005512 -287.84169)
		(end 291.556694 -287.84169)
		(width 0.20066)
		(layer "F.Cu")
		(net "M_B_CPU0_SA_DQ<24>")
	)
	(segment
		(start 293.799514 -288.266632)
		(end 292.430454 -288.266632)
		(width 0.20066)
		(layer "F.Cu")
		(net "M_B_CPU0_SA_DQ<24>")
	)
	(segment
		(start 289.239706 -287.84169)
		(end 289.231578 -287.833562)
		(width 0.101854)
		(layer "F.Cu")
		(net "M_B_CPU0_SA_DQ<24>")
	)
	(segment
		(start 289.231578 -287.833562)
		(end 288.66973 -287.833562)
		(width 0.20066)
		(layer "F.Cu")
		(net "M_B_CPU0_SA_DQ<24>")
	)
	(segment
		(start 292.430454 -288.266632)
		(end 292.005512 -287.84169)
		(width 0.20066)
		(layer "F.Cu")
		(net "M_B_CPU0_SA_DQ<24>")
	)
	(segment
		(start 287.828736 -288.505392)
		(end 287.589976 -288.266632)
		(width 0.20066)
		(layer "F.Cu")
		(net "M_B_CPU0_SA_DQ<24>")
	)
	(segment
		(start 288.28746 -288.505392)
		(end 287.828736 -288.505392)
		(width 0.20066)
		(layer "F.Cu")
		(net "M_B_CPU0_SA_DQ<24>")
	)
	(segment
		(start 294.904414 -288.266632)
		(end 293.799514 -288.266632)
		(width 0.20066)
		(layer "F.Cu")
		(net "M_B_CPU0_SA_DQ<24>")
	)
	(segment
		(start 340.424516 -263.96442)
		(end 340.424262 -263.964674)
		(width 0.20066)
		(layer "F.Cu")
		(net "M_B_CPU0_SA_DQ<24>")
	)
	(segment
		(start 289.48761 -287.84169)
		(end 289.239706 -287.84169)
		(width 0.101854)
		(layer "F.Cu")
		(net "M_B_CPU0_SA_DQ<24>")
	)
	(segment
		(start 313.212988 -280.54808)
		(end 312.001154 -281.194002)
		(width 0.18288)
		(layer "In4.Cu")
		(net "M_B_CPU0_SA_DQ<24>")
	)
	(segment
		(start 314.534804 -279.226264)
		(end 313.212988 -280.54808)
		(width 0.18288)
		(layer "In4.Cu")
		(net "M_B_CPU0_SA_DQ<24>")
	)
	(segment
		(start 304.44059 -285.411164)
		(end 303.449736 -285.411164)
		(width 0.18288)
		(layer "In4.Cu")
		(net "M_B_CPU0_SA_DQ<24>")
	)
	(segment
		(start 312.001154 -281.194002)
		(end 310.576722 -282.618434)
		(width 0.18288)
		(layer "In4.Cu")
		(net "M_B_CPU0_SA_DQ<24>")
	)
	(segment
		(start 330.724256 -265.07186)
		(end 328.27595 -265.07186)
		(width 0.18288)
		(layer "In4.Cu")
		(net "M_B_CPU0_SA_DQ<24>")
	)
	(segment
		(start 310.576722 -282.618434)
		(end 309.02021 -282.618434)
		(width 0.18288)
		(layer "In4.Cu")
		(net "M_B_CPU0_SA_DQ<24>")
	)
	(segment
		(start 303.449736 -285.411164)
		(end 302.587914 -286.272986)
		(width 0.18288)
		(layer "In4.Cu")
		(net "M_B_CPU0_SA_DQ<24>")
	)
	(segment
		(start 307.761386 -283.877258)
		(end 305.974496 -283.877258)
		(width 0.18288)
		(layer "In4.Cu")
		(net "M_B_CPU0_SA_DQ<24>")
	)
	(segment
		(start 295.506648 -287.664398)
		(end 294.904414 -288.266632)
		(width 0.18288)
		(layer "In4.Cu")
		(net "M_B_CPU0_SA_DQ<24>")
	)
	(segment
		(start 339.297518 -264.824718)
		(end 339.287104 -264.818622)
		(width 0.088646)
		(layer "In4.Cu")
		(net "M_B_CPU0_SA_DQ<24>")
	)
	(segment
		(start 301.28337 -286.593534)
		(end 299.58919 -286.593534)
		(width 0.18288)
		(layer "In4.Cu")
		(net "M_B_CPU0_SA_DQ<24>")
	)
	(segment
		(start 331.401674 -264.749026)
		(end 331.07884 -265.07186)
		(width 0.088646)
		(layer "In4.Cu")
		(net "M_B_CPU0_SA_DQ<24>")
	)
	(segment
		(start 340.054946 -264.600436)
		(end 339.671914 -264.824718)
		(width 0.088646)
		(layer "In4.Cu")
		(net "M_B_CPU0_SA_DQ<24>")
	)
	(segment
		(start 327.24725 -265.498072)
		(end 315.253116 -277.492206)
		(width 0.18288)
		(layer "In4.Cu")
		(net "M_B_CPU0_SA_DQ<24>")
	)
	(segment
		(start 295.506648 -287.20288)
		(end 295.506648 -287.664398)
		(width 0.18288)
		(layer "In4.Cu")
		(net "M_B_CPU0_SA_DQ<24>")
	)
	(segment
		(start 331.496162 -264.749026)
		(end 331.401674 -264.749026)
		(width 0.088646)
		(layer "In4.Cu")
		(net "M_B_CPU0_SA_DQ<24>")
	)
	(segment
		(start 305.974496 -283.877258)
		(end 304.44059 -285.411164)
		(width 0.18288)
		(layer "In4.Cu")
		(net "M_B_CPU0_SA_DQ<24>")
	)
	(segment
		(start 299.58919 -286.593534)
		(end 299.191172 -286.991552)
		(width 0.18288)
		(layer "In4.Cu")
		(net "M_B_CPU0_SA_DQ<24>")
	)
	(segment
		(start 302.587914 -286.272986)
		(end 301.603918 -286.272986)
		(width 0.18288)
		(layer "In4.Cu")
		(net "M_B_CPU0_SA_DQ<24>")
	)
	(segment
		(start 315.253116 -277.492206)
		(end 314.534804 -279.226264)
		(width 0.18288)
		(layer "In4.Cu")
		(net "M_B_CPU0_SA_DQ<24>")
	)
	(segment
		(start 295.717976 -286.991552)
		(end 295.506648 -287.20288)
		(width 0.18288)
		(layer "In4.Cu")
		(net "M_B_CPU0_SA_DQ<24>")
	)
	(segment
		(start 328.27595 -265.07186)
		(end 327.24725 -265.498072)
		(width 0.18288)
		(layer "In4.Cu")
		(net "M_B_CPU0_SA_DQ<24>")
	)
	(segment
		(start 299.191172 -286.991552)
		(end 295.717976 -286.991552)
		(width 0.18288)
		(layer "In4.Cu")
		(net "M_B_CPU0_SA_DQ<24>")
	)
	(segment
		(start 331.07884 -265.07186)
		(end 330.724256 -265.07186)
		(width 0.088646)
		(layer "In4.Cu")
		(net "M_B_CPU0_SA_DQ<24>")
	)
	(segment
		(start 301.603918 -286.272986)
		(end 301.28337 -286.593534)
		(width 0.18288)
		(layer "In4.Cu")
		(net "M_B_CPU0_SA_DQ<24>")
	)
	(segment
		(start 309.02021 -282.618434)
		(end 307.761386 -283.877258)
		(width 0.18288)
		(layer "In4.Cu")
		(net "M_B_CPU0_SA_DQ<24>")
	)
	(arc
		(start 333.658464 -264.824718)
		(mid 333.375762 -264.748942)
		(end 333.09306 -264.824718)
		(width 0.088646)
		(layer "In4.Cu")
		(net "M_B_CPU0_SA_DQ<24>")
	)
	(arc
		(start 340.424262 -264.50036)
		(mid 340.232953 -264.525837)
		(end 340.054946 -264.600436)
		(width 0.088646)
		(layer "In4.Cu")
		(net "M_B_CPU0_SA_DQ<24>")
	)
	(arc
		(start 332.718664 -264.824718)
		(mid 332.435962 -264.748942)
		(end 332.15326 -264.824718)
		(width 0.088646)
		(layer "In4.Cu")
		(net "M_B_CPU0_SA_DQ<24>")
	)
	(arc
		(start 336.85226 -264.824718)
		(mid 336.665062 -264.874861)
		(end 336.477864 -264.824718)
		(width 0.088646)
		(layer "In4.Cu")
		(net "M_B_CPU0_SA_DQ<24>")
	)
	(arc
		(start 334.598264 -264.824718)
		(mid 334.315562 -264.748942)
		(end 334.03286 -264.824718)
		(width 0.088646)
		(layer "In4.Cu")
		(net "M_B_CPU0_SA_DQ<24>")
	)
	(arc
		(start 335.538064 -264.824718)
		(mid 335.255362 -264.748942)
		(end 334.97266 -264.824718)
		(width 0.088646)
		(layer "In4.Cu")
		(net "M_B_CPU0_SA_DQ<24>")
	)
	(arc
		(start 339.671914 -264.824718)
		(mid 339.484716 -264.874861)
		(end 339.297518 -264.824718)
		(width 0.088646)
		(layer "In4.Cu")
		(net "M_B_CPU0_SA_DQ<24>")
	)
	(arc
		(start 336.477864 -264.824718)
		(mid 336.195162 -264.748942)
		(end 335.91246 -264.824718)
		(width 0.088646)
		(layer "In4.Cu")
		(net "M_B_CPU0_SA_DQ<24>")
	)
	(arc
		(start 334.97266 -264.824718)
		(mid 334.785462 -264.874861)
		(end 334.598264 -264.824718)
		(width 0.088646)
		(layer "In4.Cu")
		(net "M_B_CPU0_SA_DQ<24>")
	)
	(arc
		(start 333.09306 -264.824718)
		(mid 332.905862 -264.874861)
		(end 332.718664 -264.824718)
		(width 0.088646)
		(layer "In4.Cu")
		(net "M_B_CPU0_SA_DQ<24>")
	)
	(arc
		(start 338.73186 -264.824718)
		(mid 338.544662 -264.874861)
		(end 338.357464 -264.824718)
		(width 0.088646)
		(layer "In4.Cu")
		(net "M_B_CPU0_SA_DQ<24>")
	)
	(arc
		(start 332.15326 -264.824718)
		(mid 331.966062 -264.874861)
		(end 331.778864 -264.824718)
		(width 0.088646)
		(layer "In4.Cu")
		(net "M_B_CPU0_SA_DQ<24>")
	)
	(arc
		(start 339.287104 -264.818622)
		(mid 339.008672 -264.748776)
		(end 338.73186 -264.824718)
		(width 0.088646)
		(layer "In4.Cu")
		(net "M_B_CPU0_SA_DQ<24>")
	)
	(arc
		(start 335.91246 -264.824718)
		(mid 335.725262 -264.874861)
		(end 335.538064 -264.824718)
		(width 0.088646)
		(layer "In4.Cu")
		(net "M_B_CPU0_SA_DQ<24>")
	)
	(arc
		(start 334.03286 -264.824718)
		(mid 333.845662 -264.874861)
		(end 333.658464 -264.824718)
		(width 0.088646)
		(layer "In4.Cu")
		(net "M_B_CPU0_SA_DQ<24>")
	)
	(arc
		(start 338.357464 -264.824718)
		(mid 338.074762 -264.748942)
		(end 337.79206 -264.824718)
		(width 0.088646)
		(layer "In4.Cu")
		(net "M_B_CPU0_SA_DQ<24>")
	)
	(arc
		(start 331.778864 -264.824718)
		(mid 331.642495 -264.768276)
		(end 331.496162 -264.749026)
		(width 0.088646)
		(layer "In4.Cu")
		(net "M_B_CPU0_SA_DQ<24>")
	)
	(arc
		(start 337.417664 -264.824718)
		(mid 337.134962 -264.748942)
		(end 336.85226 -264.824718)
		(width 0.088646)
		(layer "In4.Cu")
		(net "M_B_CPU0_SA_DQ<24>")
	)
	(arc
		(start 337.79206 -264.824718)
		(mid 337.604862 -264.874861)
		(end 337.417664 -264.824718)
		(width 0.088646)
		(layer "In4.Cu")
		(net "M_B_CPU0_SA_DQ<24>")
	)
	(segment
		(start 299.029882 -289.11677)
		(end 297.899582 -289.11677)
		(width 0.20066)
		(layer "F.Cu")
		(net "M_B_CPU0_SA_DQ<23>")
	)
	(segment
		(start 296.42943 -289.324288)
		(end 296.217594 -289.112452)
		(width 0.20066)
		(layer "F.Cu")
		(net "M_B_CPU0_SA_DQ<23>")
	)
	(segment
		(start 295.544748 -289.541712)
		(end 295.000426 -289.541712)
		(width 0.20066)
		(layer "F.Cu")
		(net "M_B_CPU0_SA_DQ<23>")
	)
	(segment
		(start 292.689534 -289.541712)
		(end 292.67531 -289.555936)
		(width 0.101854)
		(layer "F.Cu")
		(net "M_B_CPU0_SA_DQ<23>")
	)
	(segment
		(start 295.693846 -289.392614)
		(end 295.544748 -289.541712)
		(width 0.20066)
		(layer "F.Cu")
		(net "M_B_CPU0_SA_DQ<23>")
	)
	(segment
		(start 292.05301 -289.11677)
		(end 290.355782 -289.11677)
		(width 0.20066)
		(layer "F.Cu")
		(net "M_B_CPU0_SA_DQ<23>")
	)
	(segment
		(start 295.82237 -289.112452)
		(end 295.693846 -289.240976)
		(width 0.20066)
		(layer "F.Cu")
		(net "M_B_CPU0_SA_DQ<23>")
	)
	(segment
		(start 296.875962 -289.324288)
		(end 296.42943 -289.324288)
		(width 0.20066)
		(layer "F.Cu")
		(net "M_B_CPU0_SA_DQ<23>")
	)
	(segment
		(start 292.178994 -289.242754)
		(end 292.05301 -289.11677)
		(width 0.20066)
		(layer "F.Cu")
		(net "M_B_CPU0_SA_DQ<23>")
	)
	(segment
		(start 295.000426 -289.541712)
		(end 292.927532 -289.541712)
		(width 0.1016)
		(layer "F.Cu")
		(net "M_B_CPU0_SA_DQ<23>")
	)
	(segment
		(start 292.67531 -289.555936)
		(end 292.321488 -289.555936)
		(width 0.20066)
		(layer "F.Cu")
		(net "M_B_CPU0_SA_DQ<23>")
	)
	(segment
		(start 292.178994 -289.413442)
		(end 292.178994 -289.242754)
		(width 0.20066)
		(layer "F.Cu")
		(net "M_B_CPU0_SA_DQ<23>")
	)
	(segment
		(start 296.217594 -289.112452)
		(end 295.82237 -289.112452)
		(width 0.20066)
		(layer "F.Cu")
		(net "M_B_CPU0_SA_DQ<23>")
	)
	(segment
		(start 297.08348 -289.11677)
		(end 296.875962 -289.324288)
		(width 0.20066)
		(layer "F.Cu")
		(net "M_B_CPU0_SA_DQ<23>")
	)
	(segment
		(start 295.693846 -289.240976)
		(end 295.693846 -289.392614)
		(width 0.20066)
		(layer "F.Cu")
		(net "M_B_CPU0_SA_DQ<23>")
	)
	(segment
		(start 297.899582 -289.11677)
		(end 297.08348 -289.11677)
		(width 0.20066)
		(layer "F.Cu")
		(net "M_B_CPU0_SA_DQ<23>")
	)
	(segment
		(start 292.321488 -289.555936)
		(end 292.178994 -289.413442)
		(width 0.20066)
		(layer "F.Cu")
		(net "M_B_CPU0_SA_DQ<23>")
	)
	(segment
		(start 338.074762 -263.150604)
		(end 338.074762 -263.686544)
		(width 0.20066)
		(layer "F.Cu")
		(net "M_B_CPU0_SA_DQ<23>")
	)
	(segment
		(start 292.927532 -289.541712)
		(end 292.689534 -289.541712)
		(width 0.101854)
		(layer "F.Cu")
		(net "M_B_CPU0_SA_DQ<23>")
	)
	(segment
		(start 303.59096 -281.083258)
		(end 303.369218 -281.039062)
		(width 0.18288)
		(layer "In2.Cu")
		(net "M_B_CPU0_SA_DQ<23>")
	)
	(segment
		(start 296.947336 -287.687258)
		(end 297.88485 -288.624772)
		(width 0.18288)
		(layer "In2.Cu")
		(net "M_B_CPU0_SA_DQ<23>")
	)
	(segment
		(start 305.547522 -280.214832)
		(end 305.086004 -280.214832)
		(width 0.18288)
		(layer "In2.Cu")
		(net "M_B_CPU0_SA_DQ<23>")
	)
	(segment
		(start 310.79567 -280.214832)
		(end 307.576982 -280.214832)
		(width 0.18288)
		(layer "In2.Cu")
		(net "M_B_CPU0_SA_DQ<23>")
	)
	(segment
		(start 332.15326 -263.197086)
		(end 332.15326 -263.196832)
		(width 0.088646)
		(layer "In2.Cu")
		(net "M_B_CPU0_SA_DQ<23>")
	)
	(segment
		(start 307.576982 -280.214832)
		(end 306.70754 -281.084274)
		(width 0.18288)
		(layer "In2.Cu")
		(net "M_B_CPU0_SA_DQ<23>")
	)
	(segment
		(start 333.09306 -263.196832)
		(end 333.09306 -263.197086)
		(width 0.088646)
		(layer "In2.Cu")
		(net "M_B_CPU0_SA_DQ<23>")
	)
	(segment
		(start 303.369218 -281.039062)
		(end 303.058322 -281.246834)
		(width 0.18288)
		(layer "In2.Cu")
		(net "M_B_CPU0_SA_DQ<23>")
	)
	(segment
		(start 303.058322 -281.246834)
		(end 303.01438 -281.468576)
		(width 0.18288)
		(layer "In2.Cu")
		(net "M_B_CPU0_SA_DQ<23>")
	)
	(segment
		(start 338.074762 -263.686544)
		(end 337.761834 -263.686544)
		(width 0.088646)
		(layer "In2.Cu")
		(net "M_B_CPU0_SA_DQ<23>")
	)
	(segment
		(start 328.93889 -265.397234)
		(end 327.394316 -266.941808)
		(width 0.18288)
		(layer "In2.Cu")
		(net "M_B_CPU0_SA_DQ<23>")
	)
	(segment
		(start 331.715364 -263.196832)
		(end 329.607672 -265.304524)
		(width 0.088646)
		(layer "In2.Cu")
		(net "M_B_CPU0_SA_DQ<23>")
	)
	(segment
		(start 301.897796 -282.895548)
		(end 300.593252 -282.895548)
		(width 0.18288)
		(layer "In2.Cu")
		(net "M_B_CPU0_SA_DQ<23>")
	)
	(segment
		(start 304.038254 -281.465274)
		(end 303.816766 -281.421078)
		(width 0.18288)
		(layer "In2.Cu")
		(net "M_B_CPU0_SA_DQ<23>")
	)
	(segment
		(start 329.607672 -265.304524)
		(end 329.0316 -265.304524)
		(width 0.088646)
		(layer "In2.Cu")
		(net "M_B_CPU0_SA_DQ<23>")
	)
	(segment
		(start 304.892964 -280.774394)
		(end 304.53203 -281.135328)
		(width 0.18288)
		(layer "In2.Cu")
		(net "M_B_CPU0_SA_DQ<23>")
	)
	(segment
		(start 299.88129 -282.728162)
		(end 299.68825 -282.921202)
		(width 0.18288)
		(layer "In2.Cu")
		(net "M_B_CPU0_SA_DQ<23>")
	)
	(segment
		(start 314.327286 -279.346152)
		(end 311.66435 -279.346152)
		(width 0.18288)
		(layer "In2.Cu")
		(net "M_B_CPU0_SA_DQ<23>")
	)
	(segment
		(start 327.394316 -266.941808)
		(end 324.787768 -268.021308)
		(width 0.18288)
		(layer "In2.Cu")
		(net "M_B_CPU0_SA_DQ<23>")
	)
	(segment
		(start 299.445934 -286.141668)
		(end 297.917362 -286.141668)
		(width 0.18288)
		(layer "In2.Cu")
		(net "M_B_CPU0_SA_DQ<23>")
	)
	(segment
		(start 337.761834 -263.686544)
		(end 337.69681 -263.62152)
		(width 0.088646)
		(layer "In2.Cu")
		(net "M_B_CPU0_SA_DQ<23>")
	)
	(segment
		(start 311.66435 -279.346152)
		(end 310.79567 -280.214832)
		(width 0.18288)
		(layer "In2.Cu")
		(net "M_B_CPU0_SA_DQ<23>")
	)
	(segment
		(start 303.01438 -281.468576)
		(end 303.239932 -281.806396)
		(width 0.18288)
		(layer "In2.Cu")
		(net "M_B_CPU0_SA_DQ<23>")
	)
	(segment
		(start 305.867562 -281.084274)
		(end 305.707542 -280.924254)
		(width 0.18288)
		(layer "In2.Cu")
		(net "M_B_CPU0_SA_DQ<23>")
	)
	(segment
		(start 300.425866 -282.728162)
		(end 299.88129 -282.728162)
		(width 0.18288)
		(layer "In2.Cu")
		(net "M_B_CPU0_SA_DQ<23>")
	)
	(segment
		(start 303.239932 -281.806396)
		(end 303.19599 -282.028138)
		(width 0.18288)
		(layer "In2.Cu")
		(net "M_B_CPU0_SA_DQ<23>")
	)
	(segment
		(start 297.88485 -288.624772)
		(end 298.668694 -288.624772)
		(width 0.18288)
		(layer "In2.Cu")
		(net "M_B_CPU0_SA_DQ<23>")
	)
	(segment
		(start 315.400944 -277.408132)
		(end 315.400944 -278.272494)
		(width 0.18288)
		(layer "In2.Cu")
		(net "M_B_CPU0_SA_DQ<23>")
	)
	(segment
		(start 329.0316 -265.304524)
		(end 328.93889 -265.397234)
		(width 0.088646)
		(layer "In2.Cu")
		(net "M_B_CPU0_SA_DQ<23>")
	)
	(segment
		(start 299.68825 -282.921202)
		(end 299.68825 -285.899352)
		(width 0.18288)
		(layer "In2.Cu")
		(net "M_B_CPU0_SA_DQ<23>")
	)
	(segment
		(start 298.668694 -288.624772)
		(end 298.923202 -288.730182)
		(width 0.18288)
		(layer "In2.Cu")
		(net "M_B_CPU0_SA_DQ<23>")
	)
	(segment
		(start 297.917362 -286.141668)
		(end 296.947336 -287.111694)
		(width 0.18288)
		(layer "In2.Cu")
		(net "M_B_CPU0_SA_DQ<23>")
	)
	(segment
		(start 304.53203 -281.135328)
		(end 304.038254 -281.465274)
		(width 0.18288)
		(layer "In2.Cu")
		(net "M_B_CPU0_SA_DQ<23>")
	)
	(segment
		(start 299.029882 -288.836862)
		(end 299.029882 -289.11677)
		(width 0.18288)
		(layer "In2.Cu")
		(net "M_B_CPU0_SA_DQ<23>")
	)
	(segment
		(start 298.923202 -288.730182)
		(end 299.029882 -288.836862)
		(width 0.18288)
		(layer "In2.Cu")
		(net "M_B_CPU0_SA_DQ<23>")
	)
	(segment
		(start 305.707542 -280.374852)
		(end 305.547522 -280.214832)
		(width 0.18288)
		(layer "In2.Cu")
		(net "M_B_CPU0_SA_DQ<23>")
	)
	(segment
		(start 296.947336 -287.111694)
		(end 296.947336 -287.687258)
		(width 0.18288)
		(layer "In2.Cu")
		(net "M_B_CPU0_SA_DQ<23>")
	)
	(segment
		(start 300.593252 -282.895548)
		(end 300.425866 -282.728162)
		(width 0.18288)
		(layer "In2.Cu")
		(net "M_B_CPU0_SA_DQ<23>")
	)
	(segment
		(start 299.68825 -285.899352)
		(end 299.445934 -286.141668)
		(width 0.18288)
		(layer "In2.Cu")
		(net "M_B_CPU0_SA_DQ<23>")
	)
	(segment
		(start 315.400944 -278.272494)
		(end 314.327286 -279.346152)
		(width 0.18288)
		(layer "In2.Cu")
		(net "M_B_CPU0_SA_DQ<23>")
	)
	(segment
		(start 305.707542 -280.924254)
		(end 305.707542 -280.374852)
		(width 0.18288)
		(layer "In2.Cu")
		(net "M_B_CPU0_SA_DQ<23>")
	)
	(segment
		(start 305.086004 -280.214832)
		(end 304.892964 -280.407872)
		(width 0.18288)
		(layer "In2.Cu")
		(net "M_B_CPU0_SA_DQ<23>")
	)
	(segment
		(start 306.70754 -281.084274)
		(end 305.867562 -281.084274)
		(width 0.18288)
		(layer "In2.Cu")
		(net "M_B_CPU0_SA_DQ<23>")
	)
	(segment
		(start 331.778864 -263.196832)
		(end 331.715364 -263.196832)
		(width 0.088646)
		(layer "In2.Cu")
		(net "M_B_CPU0_SA_DQ<23>")
	)
	(segment
		(start 303.19599 -282.028138)
		(end 301.897796 -282.895548)
		(width 0.18288)
		(layer "In2.Cu")
		(net "M_B_CPU0_SA_DQ<23>")
	)
	(segment
		(start 324.787768 -268.021308)
		(end 315.400944 -277.408132)
		(width 0.18288)
		(layer "In2.Cu")
		(net "M_B_CPU0_SA_DQ<23>")
	)
	(segment
		(start 304.892964 -280.407872)
		(end 304.892964 -280.774394)
		(width 0.18288)
		(layer "In2.Cu")
		(net "M_B_CPU0_SA_DQ<23>")
	)
	(segment
		(start 303.816766 -281.421078)
		(end 303.59096 -281.083258)
		(width 0.18288)
		(layer "In2.Cu")
		(net "M_B_CPU0_SA_DQ<23>")
	)
	(arc
		(start 332.718664 -263.197086)
		(mid 332.435962 -263.12131)
		(end 332.15326 -263.197086)
		(width 0.088646)
		(layer "In2.Cu")
		(net "M_B_CPU0_SA_DQ<23>")
	)
	(arc
		(start 334.97266 -263.196832)
		(mid 334.785462 -263.246975)
		(end 334.598264 -263.196832)
		(width 0.088646)
		(layer "In2.Cu")
		(net "M_B_CPU0_SA_DQ<23>")
	)
	(arc
		(start 333.09306 -263.197086)
		(mid 332.905862 -263.247229)
		(end 332.718664 -263.197086)
		(width 0.088646)
		(layer "In2.Cu")
		(net "M_B_CPU0_SA_DQ<23>")
	)
	(arc
		(start 337.69681 -263.62152)
		(mid 337.607656 -263.376033)
		(end 337.417664 -263.196832)
		(width 0.088646)
		(layer "In2.Cu")
		(net "M_B_CPU0_SA_DQ<23>")
	)
	(arc
		(start 334.03286 -263.196832)
		(mid 333.845662 -263.246975)
		(end 333.658464 -263.196832)
		(width 0.088646)
		(layer "In2.Cu")
		(net "M_B_CPU0_SA_DQ<23>")
	)
	(arc
		(start 332.15326 -263.196832)
		(mid 331.966062 -263.246975)
		(end 331.778864 -263.196832)
		(width 0.088646)
		(layer "In2.Cu")
		(net "M_B_CPU0_SA_DQ<23>")
	)
	(arc
		(start 336.477864 -263.196832)
		(mid 336.195162 -263.12109)
		(end 335.91246 -263.196832)
		(width 0.088646)
		(layer "In2.Cu")
		(net "M_B_CPU0_SA_DQ<23>")
	)
	(arc
		(start 335.91246 -263.196832)
		(mid 335.725262 -263.246975)
		(end 335.538064 -263.196832)
		(width 0.088646)
		(layer "In2.Cu")
		(net "M_B_CPU0_SA_DQ<23>")
	)
	(arc
		(start 333.658464 -263.196832)
		(mid 333.375762 -263.12109)
		(end 333.09306 -263.196832)
		(width 0.088646)
		(layer "In2.Cu")
		(net "M_B_CPU0_SA_DQ<23>")
	)
	(arc
		(start 336.85226 -263.196832)
		(mid 336.665062 -263.246975)
		(end 336.477864 -263.196832)
		(width 0.088646)
		(layer "In2.Cu")
		(net "M_B_CPU0_SA_DQ<23>")
	)
	(arc
		(start 334.598264 -263.196832)
		(mid 334.315562 -263.12109)
		(end 334.03286 -263.196832)
		(width 0.088646)
		(layer "In2.Cu")
		(net "M_B_CPU0_SA_DQ<23>")
	)
	(arc
		(start 335.538064 -263.196832)
		(mid 335.255362 -263.12109)
		(end 334.97266 -263.196832)
		(width 0.088646)
		(layer "In2.Cu")
		(net "M_B_CPU0_SA_DQ<23>")
	)
	(arc
		(start 337.417664 -263.196832)
		(mid 337.134962 -263.12109)
		(end 336.85226 -263.196832)
		(width 0.088646)
		(layer "In2.Cu")
		(net "M_B_CPU0_SA_DQ<23>")
	)
	(segment
		(start 338.544662 -263.964674)
		(end 338.544662 -264.50036)
		(width 0.20066)
		(layer "F.Cu")
		(net "M_B_CPU0_SA_DQ<22>")
	)
	(segment
		(start 299.029882 -290.816792)
		(end 297.899582 -290.816792)
		(width 0.20066)
		(layer "F.Cu")
		(net "M_B_CPU0_SA_DQ<22>")
	)
	(segment
		(start 297.899582 -290.816792)
		(end 296.584878 -290.816792)
		(width 0.20066)
		(layer "F.Cu")
		(net "M_B_CPU0_SA_DQ<22>")
	)
	(segment
		(start 292.68547 -290.39185)
		(end 292.67531 -290.38169)
		(width 0.101854)
		(layer "F.Cu")
		(net "M_B_CPU0_SA_DQ<22>")
	)
	(segment
		(start 295.944544 -291.028628)
		(end 295.777158 -290.861242)
		(width 0.20066)
		(layer "F.Cu")
		(net "M_B_CPU0_SA_DQ<22>")
	)
	(segment
		(start 292.940486 -290.39185)
		(end 292.68547 -290.39185)
		(width 0.101854)
		(layer "F.Cu")
		(net "M_B_CPU0_SA_DQ<22>")
	)
	(segment
		(start 338.544916 -263.96442)
		(end 338.544662 -263.964674)
		(width 0.20066)
		(layer "F.Cu")
		(net "M_B_CPU0_SA_DQ<22>")
	)
	(segment
		(start 292.67531 -290.38169)
		(end 291.937948 -290.38169)
		(width 0.20066)
		(layer "F.Cu")
		(net "M_B_CPU0_SA_DQ<22>")
	)
	(segment
		(start 291.937948 -290.38169)
		(end 291.502846 -290.816792)
		(width 0.20066)
		(layer "F.Cu")
		(net "M_B_CPU0_SA_DQ<22>")
	)
	(segment
		(start 295.000426 -290.39185)
		(end 292.940486 -290.39185)
		(width 0.1016)
		(layer "F.Cu")
		(net "M_B_CPU0_SA_DQ<22>")
	)
	(segment
		(start 291.502846 -290.816792)
		(end 290.355782 -290.816792)
		(width 0.20066)
		(layer "F.Cu")
		(net "M_B_CPU0_SA_DQ<22>")
	)
	(segment
		(start 295.777158 -290.861242)
		(end 295.777158 -290.535614)
		(width 0.20066)
		(layer "F.Cu")
		(net "M_B_CPU0_SA_DQ<22>")
	)
	(segment
		(start 295.777158 -290.535614)
		(end 295.633394 -290.39185)
		(width 0.20066)
		(layer "F.Cu")
		(net "M_B_CPU0_SA_DQ<22>")
	)
	(segment
		(start 296.584878 -290.816792)
		(end 296.373042 -291.028628)
		(width 0.20066)
		(layer "F.Cu")
		(net "M_B_CPU0_SA_DQ<22>")
	)
	(segment
		(start 296.373042 -291.028628)
		(end 295.944544 -291.028628)
		(width 0.20066)
		(layer "F.Cu")
		(net "M_B_CPU0_SA_DQ<22>")
	)
	(segment
		(start 295.633394 -290.39185)
		(end 295.000426 -290.39185)
		(width 0.20066)
		(layer "F.Cu")
		(net "M_B_CPU0_SA_DQ<22>")
	)
	(segment
		(start 312.49112 -280.683462)
		(end 311.87644 -281.298142)
		(width 0.18288)
		(layer "In2.Cu")
		(net "M_B_CPU0_SA_DQ<22>")
	)
	(segment
		(start 301.987458 -285.89478)
		(end 302.27905 -286.186372)
		(width 0.18288)
		(layer "In2.Cu")
		(net "M_B_CPU0_SA_DQ<22>")
	)
	(segment
		(start 338.544662 -264.50036)
		(end 338.231988 -264.50036)
		(width 0.088646)
		(layer "In2.Cu")
		(net "M_B_CPU0_SA_DQ<22>")
	)
	(segment
		(start 303.19345 -285.094172)
		(end 302.411638 -285.094172)
		(width 0.18288)
		(layer "In2.Cu")
		(net "M_B_CPU0_SA_DQ<22>")
	)
	(segment
		(start 331.479906 -264.136378)
		(end 329.863704 -265.75258)
		(width 0.088646)
		(layer "In2.Cu")
		(net "M_B_CPU0_SA_DQ<22>")
	)
	(segment
		(start 300.470824 -288.68751)
		(end 301.719234 -288.68751)
		(width 0.18288)
		(layer "In2.Cu")
		(net "M_B_CPU0_SA_DQ<22>")
	)
	(segment
		(start 304.16627 -284.04566)
		(end 303.927002 -284.04566)
		(width 0.18288)
		(layer "In2.Cu")
		(net "M_B_CPU0_SA_DQ<22>")
	)
	(segment
		(start 306.59705 -282.935172)
		(end 306.59705 -283.214572)
		(width 0.18288)
		(layer "In2.Cu")
		(net "M_B_CPU0_SA_DQ<22>")
	)
	(segment
		(start 303.569878 -283.91485)
		(end 303.195736 -284.288992)
		(width 0.18288)
		(layer "In2.Cu")
		(net "M_B_CPU0_SA_DQ<22>")
	)
	(segment
		(start 313.879484 -281.140154)
		(end 313.422792 -280.683462)
		(width 0.18288)
		(layer "In2.Cu")
		(net "M_B_CPU0_SA_DQ<22>")
	)
	(segment
		(start 303.195736 -284.514798)
		(end 303.37125 -284.690312)
		(width 0.18288)
		(layer "In2.Cu")
		(net "M_B_CPU0_SA_DQ<22>")
	)
	(segment
		(start 307.61305 -281.919172)
		(end 306.59705 -282.935172)
		(width 0.18288)
		(layer "In2.Cu")
		(net "M_B_CPU0_SA_DQ<22>")
	)
	(segment
		(start 301.59325 -287.583372)
		(end 300.691042 -287.583372)
		(width 0.18288)
		(layer "In2.Cu")
		(net "M_B_CPU0_SA_DQ<22>")
	)
	(segment
		(start 301.719234 -288.68751)
		(end 302.005492 -288.973768)
		(width 0.18288)
		(layer "In2.Cu")
		(net "M_B_CPU0_SA_DQ<22>")
	)
	(segment
		(start 325.905622 -268.388084)
		(end 325.41464 -268.87932)
		(width 0.18288)
		(layer "In2.Cu")
		(net "M_B_CPU0_SA_DQ<22>")
	)
	(segment
		(start 301.987458 -285.518352)
		(end 301.987458 -285.89478)
		(width 0.18288)
		(layer "In2.Cu")
		(net "M_B_CPU0_SA_DQ<22>")
	)
	(segment
		(start 331.566266 -264.100564)
		(end 331.479906 -264.136378)
		(width 0.088646)
		(layer "In2.Cu")
		(net "M_B_CPU0_SA_DQ<22>")
	)
	(segment
		(start 310.904636 -281.298142)
		(end 310.283606 -281.919172)
		(width 0.18288)
		(layer "In2.Cu")
		(net "M_B_CPU0_SA_DQ<22>")
	)
	(segment
		(start 300.691042 -287.583372)
		(end 300.299628 -287.974786)
		(width 0.18288)
		(layer "In2.Cu")
		(net "M_B_CPU0_SA_DQ<22>")
	)
	(segment
		(start 303.796192 -283.91485)
		(end 303.569878 -283.91485)
		(width 0.18288)
		(layer "In2.Cu")
		(net "M_B_CPU0_SA_DQ<22>")
	)
	(segment
		(start 329.56373 -265.75258)
		(end 329.445874 -265.870436)
		(width 0.088646)
		(layer "In2.Cu")
		(net "M_B_CPU0_SA_DQ<22>")
	)
	(segment
		(start 303.37125 -284.690312)
		(end 303.37125 -284.916372)
		(width 0.18288)
		(layer "In2.Cu")
		(net "M_B_CPU0_SA_DQ<22>")
	)
	(segment
		(start 338.231988 -264.50036)
		(end 338.166456 -264.434828)
		(width 0.088646)
		(layer "In2.Cu")
		(net "M_B_CPU0_SA_DQ<22>")
	)
	(segment
		(start 314.240926 -281.140154)
		(end 313.879484 -281.140154)
		(width 0.18288)
		(layer "In2.Cu")
		(net "M_B_CPU0_SA_DQ<22>")
	)
	(segment
		(start 302.411638 -285.094172)
		(end 301.987458 -285.518352)
		(width 0.18288)
		(layer "In2.Cu")
		(net "M_B_CPU0_SA_DQ<22>")
	)
	(segment
		(start 306.59705 -283.214572)
		(end 306.19065 -283.620972)
		(width 0.18288)
		(layer "In2.Cu")
		(net "M_B_CPU0_SA_DQ<22>")
	)
	(segment
		(start 303.195736 -284.288992)
		(end 303.195736 -284.514798)
		(width 0.18288)
		(layer "In2.Cu")
		(net "M_B_CPU0_SA_DQ<22>")
	)
	(segment
		(start 302.27905 -286.897572)
		(end 301.59325 -287.583372)
		(width 0.18288)
		(layer "In2.Cu")
		(net "M_B_CPU0_SA_DQ<22>")
	)
	(segment
		(start 329.445874 -265.870436)
		(end 327.653142 -267.66393)
		(width 0.18288)
		(layer "In2.Cu")
		(net "M_B_CPU0_SA_DQ<22>")
	)
	(segment
		(start 309.21579 -281.919172)
		(end 308.949598 -281.65298)
		(width 0.18288)
		(layer "In2.Cu")
		(net "M_B_CPU0_SA_DQ<22>")
	)
	(segment
		(start 302.27905 -286.186372)
		(end 302.27905 -286.897572)
		(width 0.18288)
		(layer "In2.Cu")
		(net "M_B_CPU0_SA_DQ<22>")
	)
	(segment
		(start 304.590958 -283.620972)
		(end 304.16627 -284.04566)
		(width 0.18288)
		(layer "In2.Cu")
		(net "M_B_CPU0_SA_DQ<22>")
	)
	(segment
		(start 302.005492 -289.306508)
		(end 301.772828 -289.539172)
		(width 0.18288)
		(layer "In2.Cu")
		(net "M_B_CPU0_SA_DQ<22>")
	)
	(segment
		(start 313.422792 -280.683462)
		(end 312.49112 -280.683462)
		(width 0.18288)
		(layer "In2.Cu")
		(net "M_B_CPU0_SA_DQ<22>")
	)
	(segment
		(start 308.54777 -281.65298)
		(end 308.281578 -281.919172)
		(width 0.18288)
		(layer "In2.Cu")
		(net "M_B_CPU0_SA_DQ<22>")
	)
	(segment
		(start 306.19065 -283.620972)
		(end 304.590958 -283.620972)
		(width 0.18288)
		(layer "In2.Cu")
		(net "M_B_CPU0_SA_DQ<22>")
	)
	(segment
		(start 325.41464 -268.87932)
		(end 316.488318 -277.80869)
		(width 0.18288)
		(layer "In2.Cu")
		(net "M_B_CPU0_SA_DQ<22>")
	)
	(segment
		(start 300.299628 -288.516314)
		(end 300.470824 -288.68751)
		(width 0.18288)
		(layer "In2.Cu")
		(net "M_B_CPU0_SA_DQ<22>")
	)
	(segment
		(start 300.307502 -289.539172)
		(end 299.029882 -290.816792)
		(width 0.18288)
		(layer "In2.Cu")
		(net "M_B_CPU0_SA_DQ<22>")
	)
	(segment
		(start 303.37125 -284.916372)
		(end 303.19345 -285.094172)
		(width 0.18288)
		(layer "In2.Cu")
		(net "M_B_CPU0_SA_DQ<22>")
	)
	(segment
		(start 308.281578 -281.919172)
		(end 307.61305 -281.919172)
		(width 0.18288)
		(layer "In2.Cu")
		(net "M_B_CPU0_SA_DQ<22>")
	)
	(segment
		(start 303.927002 -284.04566)
		(end 303.796192 -283.91485)
		(width 0.18288)
		(layer "In2.Cu")
		(net "M_B_CPU0_SA_DQ<22>")
	)
	(segment
		(start 300.299628 -287.974786)
		(end 300.299628 -288.516314)
		(width 0.18288)
		(layer "In2.Cu")
		(net "M_B_CPU0_SA_DQ<22>")
	)
	(segment
		(start 327.653142 -267.66393)
		(end 325.905622 -268.388084)
		(width 0.18288)
		(layer "In2.Cu")
		(net "M_B_CPU0_SA_DQ<22>")
	)
	(segment
		(start 302.005492 -288.973768)
		(end 302.005492 -289.306508)
		(width 0.18288)
		(layer "In2.Cu")
		(net "M_B_CPU0_SA_DQ<22>")
	)
	(segment
		(start 301.772828 -289.539172)
		(end 300.307502 -289.539172)
		(width 0.18288)
		(layer "In2.Cu")
		(net "M_B_CPU0_SA_DQ<22>")
	)
	(segment
		(start 316.488318 -277.80869)
		(end 316.488318 -278.891492)
		(width 0.18288)
		(layer "In2.Cu")
		(net "M_B_CPU0_SA_DQ<22>")
	)
	(segment
		(start 311.87644 -281.298142)
		(end 310.904636 -281.298142)
		(width 0.18288)
		(layer "In2.Cu")
		(net "M_B_CPU0_SA_DQ<22>")
	)
	(segment
		(start 329.863704 -265.75258)
		(end 329.56373 -265.75258)
		(width 0.088646)
		(layer "In2.Cu")
		(net "M_B_CPU0_SA_DQ<22>")
	)
	(segment
		(start 310.283606 -281.919172)
		(end 309.21579 -281.919172)
		(width 0.18288)
		(layer "In2.Cu")
		(net "M_B_CPU0_SA_DQ<22>")
	)
	(segment
		(start 316.488318 -278.891492)
		(end 314.240926 -281.140154)
		(width 0.18288)
		(layer "In2.Cu")
		(net "M_B_CPU0_SA_DQ<22>")
	)
	(segment
		(start 308.949598 -281.65298)
		(end 308.54777 -281.65298)
		(width 0.18288)
		(layer "In2.Cu")
		(net "M_B_CPU0_SA_DQ<22>")
	)
	(arc
		(start 336.007964 -264.010902)
		(mid 335.725262 -263.935126)
		(end 335.44256 -264.010902)
		(width 0.088646)
		(layer "In2.Cu")
		(net "M_B_CPU0_SA_DQ<22>")
	)
	(arc
		(start 334.128364 -264.010902)
		(mid 333.845662 -263.935126)
		(end 333.56296 -264.010902)
		(width 0.088646)
		(layer "In2.Cu")
		(net "M_B_CPU0_SA_DQ<22>")
	)
	(arc
		(start 337.32216 -264.010902)
		(mid 337.134962 -264.061045)
		(end 336.947764 -264.010902)
		(width 0.088646)
		(layer "In2.Cu")
		(net "M_B_CPU0_SA_DQ<22>")
	)
	(arc
		(start 332.248764 -264.010902)
		(mid 331.966062 -263.935126)
		(end 331.68336 -264.010902)
		(width 0.088646)
		(layer "In2.Cu")
		(net "M_B_CPU0_SA_DQ<22>")
	)
	(arc
		(start 338.166456 -264.434828)
		(mid 338.077282 -264.189786)
		(end 337.887564 -264.010902)
		(width 0.088646)
		(layer "In2.Cu")
		(net "M_B_CPU0_SA_DQ<22>")
	)
	(arc
		(start 337.887564 -264.010902)
		(mid 337.604862 -263.935126)
		(end 337.32216 -264.010902)
		(width 0.088646)
		(layer "In2.Cu")
		(net "M_B_CPU0_SA_DQ<22>")
	)
	(arc
		(start 335.068164 -264.010902)
		(mid 334.785462 -263.935126)
		(end 334.50276 -264.010902)
		(width 0.088646)
		(layer "In2.Cu")
		(net "M_B_CPU0_SA_DQ<22>")
	)
	(arc
		(start 335.44256 -264.010902)
		(mid 335.255362 -264.061045)
		(end 335.068164 -264.010902)
		(width 0.088646)
		(layer "In2.Cu")
		(net "M_B_CPU0_SA_DQ<22>")
	)
	(arc
		(start 331.68336 -264.010902)
		(mid 331.621882 -264.051904)
		(end 331.566266 -264.100564)
		(width 0.088646)
		(layer "In2.Cu")
		(net "M_B_CPU0_SA_DQ<22>")
	)
	(arc
		(start 336.38236 -264.010902)
		(mid 336.195162 -264.061045)
		(end 336.007964 -264.010902)
		(width 0.088646)
		(layer "In2.Cu")
		(net "M_B_CPU0_SA_DQ<22>")
	)
	(arc
		(start 332.62316 -264.010902)
		(mid 332.435962 -264.061045)
		(end 332.248764 -264.010902)
		(width 0.088646)
		(layer "In2.Cu")
		(net "M_B_CPU0_SA_DQ<22>")
	)
	(arc
		(start 336.947764 -264.010902)
		(mid 336.665062 -263.935126)
		(end 336.38236 -264.010902)
		(width 0.088646)
		(layer "In2.Cu")
		(net "M_B_CPU0_SA_DQ<22>")
	)
	(arc
		(start 333.56296 -264.010902)
		(mid 333.375762 -264.061045)
		(end 333.188564 -264.010902)
		(width 0.088646)
		(layer "In2.Cu")
		(net "M_B_CPU0_SA_DQ<22>")
	)
	(arc
		(start 333.188564 -264.010902)
		(mid 332.905862 -263.935126)
		(end 332.62316 -264.010902)
		(width 0.088646)
		(layer "In2.Cu")
		(net "M_B_CPU0_SA_DQ<22>")
	)
	(arc
		(start 334.50276 -264.010902)
		(mid 334.315562 -264.061045)
		(end 334.128364 -264.010902)
		(width 0.088646)
		(layer "In2.Cu")
		(net "M_B_CPU0_SA_DQ<22>")
	)
	(segment
		(start 287.801304 -290.177982)
		(end 287.589976 -289.966654)
		(width 0.20066)
		(layer "F.Cu")
		(net "M_B_CPU0_SA_DQ<21>")
	)
	(segment
		(start 288.46018 -289.695382)
		(end 288.46018 -290.02355)
		(width 0.20066)
		(layer "F.Cu")
		(net "M_B_CPU0_SA_DQ<21>")
	)
	(segment
		(start 289.240468 -289.541712)
		(end 289.231578 -289.532822)
		(width 0.1016)
		(layer "F.Cu")
		(net "M_B_CPU0_SA_DQ<21>")
	)
	(segment
		(start 291.225986 -289.541712)
		(end 289.240468 -289.541712)
		(width 0.1016)
		(layer "F.Cu")
		(net "M_B_CPU0_SA_DQ<21>")
	)
	(segment
		(start 287.589976 -289.966654)
		(end 286.255714 -289.966654)
		(width 0.20066)
		(layer "F.Cu")
		(net "M_B_CPU0_SA_DQ<21>")
	)
	(segment
		(start 289.231578 -289.532822)
		(end 288.62274 -289.532822)
		(width 0.20066)
		(layer "F.Cu")
		(net "M_B_CPU0_SA_DQ<21>")
	)
	(segment
		(start 337.134962 -263.150604)
		(end 337.134962 -263.686544)
		(width 0.20066)
		(layer "F.Cu")
		(net "M_B_CPU0_SA_DQ<21>")
	)
	(segment
		(start 288.46018 -290.02355)
		(end 288.305748 -290.177982)
		(width 0.20066)
		(layer "F.Cu")
		(net "M_B_CPU0_SA_DQ<21>")
	)
	(segment
		(start 292.160198 -289.966654)
		(end 291.735256 -289.541712)
		(width 0.20066)
		(layer "F.Cu")
		(net "M_B_CPU0_SA_DQ<21>")
	)
	(segment
		(start 288.62274 -289.532822)
		(end 288.46018 -289.695382)
		(width 0.20066)
		(layer "F.Cu")
		(net "M_B_CPU0_SA_DQ<21>")
	)
	(segment
		(start 291.735256 -289.541712)
		(end 291.556694 -289.541712)
		(width 0.20066)
		(layer "F.Cu")
		(net "M_B_CPU0_SA_DQ<21>")
	)
	(segment
		(start 293.799514 -289.966654)
		(end 292.160198 -289.966654)
		(width 0.20066)
		(layer "F.Cu")
		(net "M_B_CPU0_SA_DQ<21>")
	)
	(segment
		(start 294.904414 -289.966654)
		(end 293.799514 -289.966654)
		(width 0.20066)
		(layer "F.Cu")
		(net "M_B_CPU0_SA_DQ<21>")
	)
	(segment
		(start 288.305748 -290.177982)
		(end 287.801304 -290.177982)
		(width 0.20066)
		(layer "F.Cu")
		(net "M_B_CPU0_SA_DQ<21>")
	)
	(segment
		(start 291.556694 -289.541712)
		(end 291.225986 -289.541712)
		(width 0.101854)
		(layer "F.Cu")
		(net "M_B_CPU0_SA_DQ<21>")
	)
	(segment
		(start 300.78045 -285.500572)
		(end 300.78045 -285.957772)
		(width 0.18288)
		(layer "In2.Cu")
		(net "M_B_CPU0_SA_DQ<21>")
	)
	(segment
		(start 299.66285 -289.236658)
		(end 299.357796 -289.541712)
		(width 0.18288)
		(layer "In2.Cu")
		(net "M_B_CPU0_SA_DQ<21>")
	)
	(segment
		(start 296.723816 -289.225482)
		(end 295.645586 -289.225482)
		(width 0.18288)
		(layer "In2.Cu")
		(net "M_B_CPU0_SA_DQ<21>")
	)
	(segment
		(start 307.56225 -281.030172)
		(end 306.71389 -281.878532)
		(width 0.18288)
		(layer "In2.Cu")
		(net "M_B_CPU0_SA_DQ<21>")
	)
	(segment
		(start 337.44789 -263.686544)
		(end 337.50504 -263.629394)
		(width 0.088646)
		(layer "In2.Cu")
		(net "M_B_CPU0_SA_DQ<21>")
	)
	(segment
		(start 310.171338 -281.030172)
		(end 307.56225 -281.030172)
		(width 0.18288)
		(layer "In2.Cu")
		(net "M_B_CPU0_SA_DQ<21>")
	)
	(segment
		(start 314.328048 -280.135584)
		(end 311.733438 -280.135584)
		(width 0.18288)
		(layer "In2.Cu")
		(net "M_B_CPU0_SA_DQ<21>")
	)
	(segment
		(start 297.040046 -289.541712)
		(end 296.723816 -289.225482)
		(width 0.18288)
		(layer "In2.Cu")
		(net "M_B_CPU0_SA_DQ<21>")
	)
	(segment
		(start 311.310782 -280.55824)
		(end 310.171338 -281.030172)
		(width 0.18288)
		(layer "In2.Cu")
		(net "M_B_CPU0_SA_DQ<21>")
	)
	(segment
		(start 302.797718 -283.737558)
		(end 302.39843 -283.737558)
		(width 0.18288)
		(layer "In2.Cu")
		(net "M_B_CPU0_SA_DQ<21>")
	)
	(segment
		(start 306.71389 -281.878532)
		(end 305.559206 -281.878532)
		(width 0.18288)
		(layer "In2.Cu")
		(net "M_B_CPU0_SA_DQ<21>")
	)
	(segment
		(start 304.24374 -283.193998)
		(end 303.341278 -283.193998)
		(width 0.18288)
		(layer "In2.Cu")
		(net "M_B_CPU0_SA_DQ<21>")
	)
	(segment
		(start 302.099726 -283.438854)
		(end 300.698154 -283.438854)
		(width 0.18288)
		(layer "In2.Cu")
		(net "M_B_CPU0_SA_DQ<21>")
	)
	(segment
		(start 315.908944 -277.6474)
		(end 315.908944 -278.554688)
		(width 0.18288)
		(layer "In2.Cu")
		(net "M_B_CPU0_SA_DQ<21>")
	)
	(segment
		(start 331.793342 -263.436862)
		(end 329.690222 -265.539982)
		(width 0.088646)
		(layer "In2.Cu")
		(net "M_B_CPU0_SA_DQ<21>")
	)
	(segment
		(start 295.645586 -289.225482)
		(end 294.904414 -289.966654)
		(width 0.18288)
		(layer "In2.Cu")
		(net "M_B_CPU0_SA_DQ<21>")
	)
	(segment
		(start 311.733438 -280.135584)
		(end 311.310782 -280.55824)
		(width 0.18288)
		(layer "In2.Cu")
		(net "M_B_CPU0_SA_DQ<21>")
	)
	(segment
		(start 300.78045 -285.957772)
		(end 299.66285 -287.075372)
		(width 0.18288)
		(layer "In2.Cu")
		(net "M_B_CPU0_SA_DQ<21>")
	)
	(segment
		(start 327.451974 -267.3731)
		(end 325.285354 -268.27099)
		(width 0.18288)
		(layer "In2.Cu")
		(net "M_B_CPU0_SA_DQ<21>")
	)
	(segment
		(start 337.33105 -263.367266)
		(end 337.32216 -263.362186)
		(width 0.088646)
		(layer "In2.Cu")
		(net "M_B_CPU0_SA_DQ<21>")
	)
	(segment
		(start 303.341278 -283.193998)
		(end 302.797718 -283.737558)
		(width 0.18288)
		(layer "In2.Cu")
		(net "M_B_CPU0_SA_DQ<21>")
	)
	(segment
		(start 325.285354 -268.27099)
		(end 315.908944 -277.6474)
		(width 0.18288)
		(layer "In2.Cu")
		(net "M_B_CPU0_SA_DQ<21>")
	)
	(segment
		(start 315.908944 -278.554688)
		(end 314.328048 -280.135584)
		(width 0.18288)
		(layer "In2.Cu")
		(net "M_B_CPU0_SA_DQ<21>")
	)
	(segment
		(start 305.559206 -281.878532)
		(end 304.24374 -283.193998)
		(width 0.18288)
		(layer "In2.Cu")
		(net "M_B_CPU0_SA_DQ<21>")
	)
	(segment
		(start 299.357796 -289.541712)
		(end 297.040046 -289.541712)
		(width 0.18288)
		(layer "In2.Cu")
		(net "M_B_CPU0_SA_DQ<21>")
	)
	(segment
		(start 300.698154 -283.438854)
		(end 300.37405 -283.762958)
		(width 0.18288)
		(layer "In2.Cu")
		(net "M_B_CPU0_SA_DQ<21>")
	)
	(segment
		(start 329.690222 -265.539982)
		(end 329.285092 -265.539982)
		(width 0.088646)
		(layer "In2.Cu")
		(net "M_B_CPU0_SA_DQ<21>")
	)
	(segment
		(start 329.200256 -265.624818)
		(end 327.451974 -267.3731)
		(width 0.18288)
		(layer "In2.Cu")
		(net "M_B_CPU0_SA_DQ<21>")
	)
	(segment
		(start 329.285092 -265.539982)
		(end 329.200256 -265.624818)
		(width 0.088646)
		(layer "In2.Cu")
		(net "M_B_CPU0_SA_DQ<21>")
	)
	(segment
		(start 331.92974 -263.436862)
		(end 331.793342 -263.436862)
		(width 0.088646)
		(layer "In2.Cu")
		(net "M_B_CPU0_SA_DQ<21>")
	)
	(segment
		(start 337.134962 -263.686544)
		(end 337.44789 -263.686544)
		(width 0.088646)
		(layer "In2.Cu")
		(net "M_B_CPU0_SA_DQ<21>")
	)
	(segment
		(start 302.39843 -283.737558)
		(end 302.099726 -283.438854)
		(width 0.18288)
		(layer "In2.Cu")
		(net "M_B_CPU0_SA_DQ<21>")
	)
	(segment
		(start 300.37405 -285.094172)
		(end 300.78045 -285.500572)
		(width 0.18288)
		(layer "In2.Cu")
		(net "M_B_CPU0_SA_DQ<21>")
	)
	(segment
		(start 300.37405 -283.762958)
		(end 300.37405 -285.094172)
		(width 0.18288)
		(layer "In2.Cu")
		(net "M_B_CPU0_SA_DQ<21>")
	)
	(segment
		(start 299.66285 -287.075372)
		(end 299.66285 -289.236658)
		(width 0.18288)
		(layer "In2.Cu")
		(net "M_B_CPU0_SA_DQ<21>")
	)
	(arc
		(start 332.62316 -263.362186)
		(mid 332.435962 -263.312043)
		(end 332.248764 -263.362186)
		(width 0.088646)
		(layer "In2.Cu")
		(net "M_B_CPU0_SA_DQ<21>")
	)
	(arc
		(start 337.32216 -263.362186)
		(mid 337.134962 -263.312043)
		(end 336.947764 -263.362186)
		(width 0.088646)
		(layer "In2.Cu")
		(net "M_B_CPU0_SA_DQ<21>")
	)
	(arc
		(start 336.947764 -263.362186)
		(mid 336.665062 -263.437928)
		(end 336.38236 -263.362186)
		(width 0.088646)
		(layer "In2.Cu")
		(net "M_B_CPU0_SA_DQ<21>")
	)
	(arc
		(start 335.068164 -263.362186)
		(mid 334.785462 -263.437928)
		(end 334.50276 -263.362186)
		(width 0.088646)
		(layer "In2.Cu")
		(net "M_B_CPU0_SA_DQ<21>")
	)
	(arc
		(start 332.248764 -263.362186)
		(mid 332.09478 -263.423154)
		(end 331.92974 -263.436862)
		(width 0.088646)
		(layer "In2.Cu")
		(net "M_B_CPU0_SA_DQ<21>")
	)
	(arc
		(start 333.56296 -263.362186)
		(mid 333.375762 -263.312043)
		(end 333.188564 -263.362186)
		(width 0.088646)
		(layer "In2.Cu")
		(net "M_B_CPU0_SA_DQ<21>")
	)
	(arc
		(start 336.38236 -263.362186)
		(mid 336.195162 -263.312043)
		(end 336.007964 -263.362186)
		(width 0.088646)
		(layer "In2.Cu")
		(net "M_B_CPU0_SA_DQ<21>")
	)
	(arc
		(start 334.128364 -263.362186)
		(mid 333.845662 -263.437928)
		(end 333.56296 -263.362186)
		(width 0.088646)
		(layer "In2.Cu")
		(net "M_B_CPU0_SA_DQ<21>")
	)
	(arc
		(start 335.44256 -263.362186)
		(mid 335.255362 -263.312043)
		(end 335.068164 -263.362186)
		(width 0.088646)
		(layer "In2.Cu")
		(net "M_B_CPU0_SA_DQ<21>")
	)
	(arc
		(start 337.50504 -263.629394)
		(mid 337.446921 -263.479153)
		(end 337.33105 -263.367266)
		(width 0.088646)
		(layer "In2.Cu")
		(net "M_B_CPU0_SA_DQ<21>")
	)
	(arc
		(start 334.50276 -263.362186)
		(mid 334.315562 -263.312043)
		(end 334.128364 -263.362186)
		(width 0.088646)
		(layer "In2.Cu")
		(net "M_B_CPU0_SA_DQ<21>")
	)
	(arc
		(start 333.188564 -263.362186)
		(mid 332.905862 -263.437962)
		(end 332.62316 -263.362186)
		(width 0.088646)
		(layer "In2.Cu")
		(net "M_B_CPU0_SA_DQ<21>")
	)
	(arc
		(start 336.007964 -263.362186)
		(mid 335.725262 -263.437928)
		(end 335.44256 -263.362186)
		(width 0.088646)
		(layer "In2.Cu")
		(net "M_B_CPU0_SA_DQ<21>")
	)
	(segment
		(start 288.46018 -291.443156)
		(end 288.46018 -291.732716)
		(width 0.20066)
		(layer "F.Cu")
		(net "M_B_CPU0_SA_DQ<20>")
	)
	(segment
		(start 289.48761 -291.241734)
		(end 289.239706 -291.241734)
		(width 0.101854)
		(layer "F.Cu")
		(net "M_B_CPU0_SA_DQ<20>")
	)
	(segment
		(start 294.904414 -291.666676)
		(end 293.799514 -291.666676)
		(width 0.20066)
		(layer "F.Cu")
		(net "M_B_CPU0_SA_DQ<20>")
	)
	(segment
		(start 336.665316 -263.96442)
		(end 336.665316 -264.500106)
		(width 0.20066)
		(layer "F.Cu")
		(net "M_B_CPU0_SA_DQ<20>")
	)
	(segment
		(start 287.828736 -291.905436)
		(end 287.589976 -291.666676)
		(width 0.20066)
		(layer "F.Cu")
		(net "M_B_CPU0_SA_DQ<20>")
	)
	(segment
		(start 289.239706 -291.241734)
		(end 289.231578 -291.233606)
		(width 0.101854)
		(layer "F.Cu")
		(net "M_B_CPU0_SA_DQ<20>")
	)
	(segment
		(start 288.66973 -291.233606)
		(end 288.46018 -291.443156)
		(width 0.20066)
		(layer "F.Cu")
		(net "M_B_CPU0_SA_DQ<20>")
	)
	(segment
		(start 292.005512 -291.241734)
		(end 291.556694 -291.241734)
		(width 0.20066)
		(layer "F.Cu")
		(net "M_B_CPU0_SA_DQ<20>")
	)
	(segment
		(start 289.231578 -291.233606)
		(end 288.66973 -291.233606)
		(width 0.20066)
		(layer "F.Cu")
		(net "M_B_CPU0_SA_DQ<20>")
	)
	(segment
		(start 288.28746 -291.905436)
		(end 287.828736 -291.905436)
		(width 0.20066)
		(layer "F.Cu")
		(net "M_B_CPU0_SA_DQ<20>")
	)
	(segment
		(start 336.665316 -264.500106)
		(end 336.665062 -264.50036)
		(width 0.20066)
		(layer "F.Cu")
		(net "M_B_CPU0_SA_DQ<20>")
	)
	(segment
		(start 292.430454 -291.666676)
		(end 292.005512 -291.241734)
		(width 0.20066)
		(layer "F.Cu")
		(net "M_B_CPU0_SA_DQ<20>")
	)
	(segment
		(start 287.589976 -291.666676)
		(end 286.255714 -291.666676)
		(width 0.20066)
		(layer "F.Cu")
		(net "M_B_CPU0_SA_DQ<20>")
	)
	(segment
		(start 288.46018 -291.732716)
		(end 288.28746 -291.905436)
		(width 0.20066)
		(layer "F.Cu")
		(net "M_B_CPU0_SA_DQ<20>")
	)
	(segment
		(start 293.799514 -291.666676)
		(end 292.430454 -291.666676)
		(width 0.20066)
		(layer "F.Cu")
		(net "M_B_CPU0_SA_DQ<20>")
	)
	(segment
		(start 291.556694 -291.241734)
		(end 289.48761 -291.241734)
		(width 0.1016)
		(layer "F.Cu")
		(net "M_B_CPU0_SA_DQ<20>")
	)
	(segment
		(start 307.334666 -284.117796)
		(end 307.03266 -284.419802)
		(width 0.18288)
		(layer "In2.Cu")
		(net "M_B_CPU0_SA_DQ<20>")
	)
	(segment
		(start 329.851258 -265.958574)
		(end 329.692762 -266.11707)
		(width 0.088646)
		(layer "In2.Cu")
		(net "M_B_CPU0_SA_DQ<20>")
	)
	(segment
		(start 336.977736 -264.50036)
		(end 337.03514 -264.442956)
		(width 0.088646)
		(layer "In2.Cu")
		(net "M_B_CPU0_SA_DQ<20>")
	)
	(segment
		(start 309.25262 -283.229558)
		(end 308.744366 -283.229558)
		(width 0.18288)
		(layer "In2.Cu")
		(net "M_B_CPU0_SA_DQ<20>")
	)
	(segment
		(start 306.796694 -284.419802)
		(end 306.626514 -284.249622)
		(width 0.18288)
		(layer "In2.Cu")
		(net "M_B_CPU0_SA_DQ<20>")
	)
	(segment
		(start 297.01744 -291.196014)
		(end 295.375076 -291.196014)
		(width 0.18288)
		(layer "In2.Cu")
		(net "M_B_CPU0_SA_DQ<20>")
	)
	(segment
		(start 336.86115 -264.181082)
		(end 336.85226 -264.176002)
		(width 0.088646)
		(layer "In2.Cu")
		(net "M_B_CPU0_SA_DQ<20>")
	)
	(segment
		(start 299.301662 -291.241734)
		(end 298.764198 -291.241734)
		(width 0.18288)
		(layer "In2.Cu")
		(net "M_B_CPU0_SA_DQ<20>")
	)
	(segment
		(start 299.346112 -291.286184)
		(end 299.301662 -291.241734)
		(width 0.18288)
		(layer "In2.Cu")
		(net "M_B_CPU0_SA_DQ<20>")
	)
	(segment
		(start 307.03266 -284.419802)
		(end 306.796694 -284.419802)
		(width 0.18288)
		(layer "In2.Cu")
		(net "M_B_CPU0_SA_DQ<20>")
	)
	(segment
		(start 297.294554 -291.473128)
		(end 297.01744 -291.196014)
		(width 0.18288)
		(layer "In2.Cu")
		(net "M_B_CPU0_SA_DQ<20>")
	)
	(segment
		(start 295.375076 -291.196014)
		(end 294.904414 -291.666676)
		(width 0.18288)
		(layer "In2.Cu")
		(net "M_B_CPU0_SA_DQ<20>")
	)
	(segment
		(start 329.959462 -265.958574)
		(end 329.851258 -265.958574)
		(width 0.088646)
		(layer "In2.Cu")
		(net "M_B_CPU0_SA_DQ<20>")
	)
	(segment
		(start 307.184552 -283.741622)
		(end 307.334666 -283.891736)
		(width 0.18288)
		(layer "In2.Cu")
		(net "M_B_CPU0_SA_DQ<20>")
	)
	(segment
		(start 336.665062 -264.50036)
		(end 336.977736 -264.50036)
		(width 0.088646)
		(layer "In2.Cu")
		(net "M_B_CPU0_SA_DQ<20>")
	)
	(segment
		(start 308.424326 -282.721558)
		(end 307.60162 -282.721558)
		(width 0.18288)
		(layer "In2.Cu")
		(net "M_B_CPU0_SA_DQ<20>")
	)
	(segment
		(start 301.176944 -291.286184)
		(end 299.346112 -291.286184)
		(width 0.18288)
		(layer "In2.Cu")
		(net "M_B_CPU0_SA_DQ<20>")
	)
	(segment
		(start 308.744366 -283.229558)
		(end 308.584346 -283.069538)
		(width 0.18288)
		(layer "In2.Cu")
		(net "M_B_CPU0_SA_DQ<20>")
	)
	(segment
		(start 327.85558 -267.954252)
		(end 326.508618 -268.51229)
		(width 0.18288)
		(layer "In2.Cu")
		(net "M_B_CPU0_SA_DQ<20>")
	)
	(segment
		(start 308.584346 -283.069538)
		(end 308.584346 -282.881578)
		(width 0.18288)
		(layer "In2.Cu")
		(net "M_B_CPU0_SA_DQ<20>")
	)
	(segment
		(start 310.506364 -282.721558)
		(end 309.57266 -282.721558)
		(width 0.18288)
		(layer "In2.Cu")
		(net "M_B_CPU0_SA_DQ<20>")
	)
	(segment
		(start 304.116486 -285.334456)
		(end 302.971962 -286.47898)
		(width 0.18288)
		(layer "In2.Cu")
		(net "M_B_CPU0_SA_DQ<20>")
	)
	(segment
		(start 302.971962 -289.491166)
		(end 301.176944 -291.286184)
		(width 0.18288)
		(layer "In2.Cu")
		(net "M_B_CPU0_SA_DQ<20>")
	)
	(segment
		(start 309.41264 -283.069538)
		(end 309.25262 -283.229558)
		(width 0.18288)
		(layer "In2.Cu")
		(net "M_B_CPU0_SA_DQ<20>")
	)
	(segment
		(start 317.008002 -278.012906)
		(end 317.008002 -279.091644)
		(width 0.18288)
		(layer "In2.Cu")
		(net "M_B_CPU0_SA_DQ<20>")
	)
	(segment
		(start 317.008002 -279.091644)
		(end 314.254896 -281.84475)
		(width 0.18288)
		(layer "In2.Cu")
		(net "M_B_CPU0_SA_DQ<20>")
	)
	(segment
		(start 311.383172 -281.84475)
		(end 310.506364 -282.721558)
		(width 0.18288)
		(layer "In2.Cu")
		(net "M_B_CPU0_SA_DQ<20>")
	)
	(segment
		(start 307.60162 -282.721558)
		(end 307.184552 -283.138626)
		(width 0.18288)
		(layer "In2.Cu")
		(net "M_B_CPU0_SA_DQ<20>")
	)
	(segment
		(start 331.700886 -264.235184)
		(end 331.455522 -264.480548)
		(width 0.088646)
		(layer "In2.Cu")
		(net "M_B_CPU0_SA_DQ<20>")
	)
	(segment
		(start 308.584346 -282.881578)
		(end 308.424326 -282.721558)
		(width 0.18288)
		(layer "In2.Cu")
		(net "M_B_CPU0_SA_DQ<20>")
	)
	(segment
		(start 314.254896 -281.84475)
		(end 311.383172 -281.84475)
		(width 0.18288)
		(layer "In2.Cu")
		(net "M_B_CPU0_SA_DQ<20>")
	)
	(segment
		(start 306.4002 -284.249622)
		(end 305.315366 -285.334456)
		(width 0.18288)
		(layer "In2.Cu")
		(net "M_B_CPU0_SA_DQ<20>")
	)
	(segment
		(start 331.424788 -264.493248)
		(end 329.959462 -265.958574)
		(width 0.088646)
		(layer "In2.Cu")
		(net "M_B_CPU0_SA_DQ<20>")
	)
	(segment
		(start 305.315366 -285.334456)
		(end 304.116486 -285.334456)
		(width 0.18288)
		(layer "In2.Cu")
		(net "M_B_CPU0_SA_DQ<20>")
	)
	(segment
		(start 306.626514 -284.249622)
		(end 306.4002 -284.249622)
		(width 0.18288)
		(layer "In2.Cu")
		(net "M_B_CPU0_SA_DQ<20>")
	)
	(segment
		(start 309.41264 -282.881578)
		(end 309.41264 -283.069538)
		(width 0.18288)
		(layer "In2.Cu")
		(net "M_B_CPU0_SA_DQ<20>")
	)
	(segment
		(start 329.692762 -266.11707)
		(end 327.85558 -267.954252)
		(width 0.18288)
		(layer "In2.Cu")
		(net "M_B_CPU0_SA_DQ<20>")
	)
	(segment
		(start 331.455522 -264.480548)
		(end 331.424788 -264.493248)
		(width 0.088646)
		(layer "In2.Cu")
		(net "M_B_CPU0_SA_DQ<20>")
	)
	(segment
		(start 309.57266 -282.721558)
		(end 309.41264 -282.881578)
		(width 0.18288)
		(layer "In2.Cu")
		(net "M_B_CPU0_SA_DQ<20>")
	)
	(segment
		(start 326.508618 -268.51229)
		(end 317.008002 -278.012906)
		(width 0.18288)
		(layer "In2.Cu")
		(net "M_B_CPU0_SA_DQ<20>")
	)
	(segment
		(start 302.971962 -286.47898)
		(end 302.971962 -289.491166)
		(width 0.18288)
		(layer "In2.Cu")
		(net "M_B_CPU0_SA_DQ<20>")
	)
	(segment
		(start 307.184552 -283.138626)
		(end 307.184552 -283.741622)
		(width 0.18288)
		(layer "In2.Cu")
		(net "M_B_CPU0_SA_DQ<20>")
	)
	(segment
		(start 298.764198 -291.241734)
		(end 298.532804 -291.473128)
		(width 0.18288)
		(layer "In2.Cu")
		(net "M_B_CPU0_SA_DQ<20>")
	)
	(segment
		(start 298.532804 -291.473128)
		(end 297.294554 -291.473128)
		(width 0.18288)
		(layer "In2.Cu")
		(net "M_B_CPU0_SA_DQ<20>")
	)
	(segment
		(start 307.334666 -283.891736)
		(end 307.334666 -284.117796)
		(width 0.18288)
		(layer "In2.Cu")
		(net "M_B_CPU0_SA_DQ<20>")
	)
	(arc
		(start 332.718664 -264.176002)
		(mid 332.435962 -264.251778)
		(end 332.15326 -264.176002)
		(width 0.088646)
		(layer "In2.Cu")
		(net "M_B_CPU0_SA_DQ<20>")
	)
	(arc
		(start 332.15326 -264.176002)
		(mid 331.966062 -264.125859)
		(end 331.778864 -264.176002)
		(width 0.088646)
		(layer "In2.Cu")
		(net "M_B_CPU0_SA_DQ<20>")
	)
	(arc
		(start 334.03286 -264.176002)
		(mid 333.845662 -264.125859)
		(end 333.658464 -264.176002)
		(width 0.088646)
		(layer "In2.Cu")
		(net "M_B_CPU0_SA_DQ<20>")
	)
	(arc
		(start 336.85226 -264.176002)
		(mid 336.665062 -264.125859)
		(end 336.477864 -264.176002)
		(width 0.088646)
		(layer "In2.Cu")
		(net "M_B_CPU0_SA_DQ<20>")
	)
	(arc
		(start 331.778864 -264.176002)
		(mid 331.737934 -264.203035)
		(end 331.700886 -264.235184)
		(width 0.088646)
		(layer "In2.Cu")
		(net "M_B_CPU0_SA_DQ<20>")
	)
	(arc
		(start 337.03514 -264.442956)
		(mid 336.976984 -264.292843)
		(end 336.86115 -264.181082)
		(width 0.088646)
		(layer "In2.Cu")
		(net "M_B_CPU0_SA_DQ<20>")
	)
	(arc
		(start 334.97266 -264.176002)
		(mid 334.785462 -264.125859)
		(end 334.598264 -264.176002)
		(width 0.088646)
		(layer "In2.Cu")
		(net "M_B_CPU0_SA_DQ<20>")
	)
	(arc
		(start 335.91246 -264.176002)
		(mid 335.725262 -264.125859)
		(end 335.538064 -264.176002)
		(width 0.088646)
		(layer "In2.Cu")
		(net "M_B_CPU0_SA_DQ<20>")
	)
	(arc
		(start 334.598264 -264.176002)
		(mid 334.315562 -264.251778)
		(end 334.03286 -264.176002)
		(width 0.088646)
		(layer "In2.Cu")
		(net "M_B_CPU0_SA_DQ<20>")
	)
	(arc
		(start 333.09306 -264.176002)
		(mid 332.905862 -264.125859)
		(end 332.718664 -264.176002)
		(width 0.088646)
		(layer "In2.Cu")
		(net "M_B_CPU0_SA_DQ<20>")
	)
	(arc
		(start 333.658464 -264.176002)
		(mid 333.375762 -264.251778)
		(end 333.09306 -264.176002)
		(width 0.088646)
		(layer "In2.Cu")
		(net "M_B_CPU0_SA_DQ<20>")
	)
	(arc
		(start 336.477864 -264.176002)
		(mid 336.195162 -264.251778)
		(end 335.91246 -264.176002)
		(width 0.088646)
		(layer "In2.Cu")
		(net "M_B_CPU0_SA_DQ<20>")
	)
	(arc
		(start 335.538064 -264.176002)
		(mid 335.255362 -264.251778)
		(end 334.97266 -264.176002)
		(width 0.088646)
		(layer "In2.Cu")
		(net "M_B_CPU0_SA_DQ<20>")
	)
	(segment
		(start 289.231578 -314.18276)
		(end 288.62274 -314.18276)
		(width 0.20066)
		(layer "F.Cu")
		(net "M_B_CPU0_SA_DQ<1>")
	)
	(segment
		(start 288.46018 -314.673488)
		(end 288.305748 -314.82792)
		(width 0.20066)
		(layer "F.Cu")
		(net "M_B_CPU0_SA_DQ<1>")
	)
	(segment
		(start 289.240468 -314.19165)
		(end 289.231578 -314.18276)
		(width 0.1016)
		(layer "F.Cu")
		(net "M_B_CPU0_SA_DQ<1>")
	)
	(segment
		(start 336.665316 -275.35886)
		(end 336.665316 -275.894292)
		(width 0.20066)
		(layer "F.Cu")
		(net "M_B_CPU0_SA_DQ<1>")
	)
	(segment
		(start 287.801304 -314.82792)
		(end 287.589976 -314.616592)
		(width 0.20066)
		(layer "F.Cu")
		(net "M_B_CPU0_SA_DQ<1>")
	)
	(segment
		(start 292.160198 -314.616592)
		(end 291.735256 -314.19165)
		(width 0.20066)
		(layer "F.Cu")
		(net "M_B_CPU0_SA_DQ<1>")
	)
	(segment
		(start 288.305748 -314.82792)
		(end 287.801304 -314.82792)
		(width 0.20066)
		(layer "F.Cu")
		(net "M_B_CPU0_SA_DQ<1>")
	)
	(segment
		(start 291.735256 -314.19165)
		(end 291.556694 -314.19165)
		(width 0.20066)
		(layer "F.Cu")
		(net "M_B_CPU0_SA_DQ<1>")
	)
	(segment
		(start 293.799514 -314.616592)
		(end 292.160198 -314.616592)
		(width 0.20066)
		(layer "F.Cu")
		(net "M_B_CPU0_SA_DQ<1>")
	)
	(segment
		(start 288.46018 -314.34532)
		(end 288.46018 -314.673488)
		(width 0.20066)
		(layer "F.Cu")
		(net "M_B_CPU0_SA_DQ<1>")
	)
	(segment
		(start 287.589976 -314.616592)
		(end 286.255714 -314.616592)
		(width 0.20066)
		(layer "F.Cu")
		(net "M_B_CPU0_SA_DQ<1>")
	)
	(segment
		(start 291.556694 -314.19165)
		(end 291.225986 -314.19165)
		(width 0.101854)
		(layer "F.Cu")
		(net "M_B_CPU0_SA_DQ<1>")
	)
	(segment
		(start 294.904414 -314.616592)
		(end 293.799514 -314.616592)
		(width 0.20066)
		(layer "F.Cu")
		(net "M_B_CPU0_SA_DQ<1>")
	)
	(segment
		(start 288.62274 -314.18276)
		(end 288.46018 -314.34532)
		(width 0.20066)
		(layer "F.Cu")
		(net "M_B_CPU0_SA_DQ<1>")
	)
	(segment
		(start 291.225986 -314.19165)
		(end 289.240468 -314.19165)
		(width 0.1016)
		(layer "F.Cu")
		(net "M_B_CPU0_SA_DQ<1>")
	)
	(arc
		(start 336.665316 -275.894292)
		(mid 336.665258 -275.894584)
		(end 336.665062 -275.8948)
		(width 0.20066)
		(layer "F.Cu")
		(net "M_B_CPU0_SA_DQ<1>")
	)
	(segment
		(start 333.845662 -281.343354)
		(end 333.657448 -281.343354)
		(width 0.088646)
		(layer "In2.Cu")
		(net "M_B_CPU0_SA_DQ<1>")
	)
	(segment
		(start 332.039468 -285.275274)
		(end 331.483208 -286.617918)
		(width 0.18288)
		(layer "In2.Cu")
		(net "M_B_CPU0_SA_DQ<1>")
	)
	(segment
		(start 301.382176 -315.171328)
		(end 301.200566 -314.989718)
		(width 0.18288)
		(layer "In2.Cu")
		(net "M_B_CPU0_SA_DQ<1>")
	)
	(segment
		(start 336.665062 -275.8948)
		(end 336.762344 -276.39518)
		(width 0.088646)
		(layer "In2.Cu")
		(net "M_B_CPU0_SA_DQ<1>")
	)
	(segment
		(start 297.042078 -314.173616)
		(end 296.524934 -314.173616)
		(width 0.18288)
		(layer "In2.Cu")
		(net "M_B_CPU0_SA_DQ<1>")
	)
	(segment
		(start 332.160626 -282.407106)
		(end 332.160626 -284.982666)
		(width 0.18288)
		(layer "In2.Cu")
		(net "M_B_CPU0_SA_DQ<1>")
	)
	(segment
		(start 333.657448 -281.343354)
		(end 333.512922 -281.48788)
		(width 0.088646)
		(layer "In2.Cu")
		(net "M_B_CPU0_SA_DQ<1>")
	)
	(segment
		(start 307.278532 -316.206886)
		(end 306.933092 -315.861446)
		(width 0.18288)
		(layer "In2.Cu")
		(net "M_B_CPU0_SA_DQ<1>")
	)
	(segment
		(start 336.290412 -279.150318)
		(end 336.290412 -279.160224)
		(width 0.088646)
		(layer "In2.Cu")
		(net "M_B_CPU0_SA_DQ<1>")
	)
	(segment
		(start 296.224452 -314.474098)
		(end 295.929558 -314.474098)
		(width 0.18288)
		(layer "In2.Cu")
		(net "M_B_CPU0_SA_DQ<1>")
	)
	(segment
		(start 303.218088 -316.224158)
		(end 302.436022 -316.224158)
		(width 0.18288)
		(layer "In2.Cu")
		(net "M_B_CPU0_SA_DQ<1>")
	)
	(segment
		(start 299.186854 -314.19419)
		(end 298.16171 -314.19419)
		(width 0.18288)
		(layer "In2.Cu")
		(net "M_B_CPU0_SA_DQ<1>")
	)
	(segment
		(start 323.73697 -303.415446)
		(end 322.431156 -306.568094)
		(width 0.18288)
		(layer "In2.Cu")
		(net "M_B_CPU0_SA_DQ<1>")
	)
	(segment
		(start 303.49698 -315.771276)
		(end 303.334166 -315.93409)
		(width 0.18288)
		(layer "In2.Cu")
		(net "M_B_CPU0_SA_DQ<1>")
	)
	(segment
		(start 308.097936 -315.902086)
		(end 307.793136 -316.206886)
		(width 0.18288)
		(layer "In2.Cu")
		(net "M_B_CPU0_SA_DQ<1>")
	)
	(segment
		(start 306.311046 -315.861446)
		(end 306.156106 -316.016386)
		(width 0.18288)
		(layer "In2.Cu")
		(net "M_B_CPU0_SA_DQ<1>")
	)
	(segment
		(start 296.524934 -314.173616)
		(end 296.224452 -314.474098)
		(width 0.18288)
		(layer "In2.Cu")
		(net "M_B_CPU0_SA_DQ<1>")
	)
	(segment
		(start 311.76087 -315.052964)
		(end 310.911748 -315.902086)
		(width 0.18288)
		(layer "In2.Cu")
		(net "M_B_CPU0_SA_DQ<1>")
	)
	(segment
		(start 307.793136 -316.206886)
		(end 307.278532 -316.206886)
		(width 0.18288)
		(layer "In2.Cu")
		(net "M_B_CPU0_SA_DQ<1>")
	)
	(segment
		(start 334.598264 -280.453846)
		(end 334.589374 -280.458926)
		(width 0.088646)
		(layer "In2.Cu")
		(net "M_B_CPU0_SA_DQ<1>")
	)
	(segment
		(start 336.938874 -277.027894)
		(end 336.947764 -277.032974)
		(width 0.088646)
		(layer "In2.Cu")
		(net "M_B_CPU0_SA_DQ<1>")
	)
	(segment
		(start 303.334166 -315.93409)
		(end 303.334166 -316.10808)
		(width 0.18288)
		(layer "In2.Cu")
		(net "M_B_CPU0_SA_DQ<1>")
	)
	(segment
		(start 324.367906 -300.245018)
		(end 323.73697 -303.415446)
		(width 0.18288)
		(layer "In2.Cu")
		(net "M_B_CPU0_SA_DQ<1>")
	)
	(segment
		(start 336.762344 -276.39518)
		(end 336.760312 -276.708616)
		(width 0.088646)
		(layer "In2.Cu")
		(net "M_B_CPU0_SA_DQ<1>")
	)
	(segment
		(start 328.972672 -289.128454)
		(end 324.367906 -300.245018)
		(width 0.18288)
		(layer "In2.Cu")
		(net "M_B_CPU0_SA_DQ<1>")
	)
	(segment
		(start 314.566046 -314.433204)
		(end 314.566046 -314.746132)
		(width 0.18288)
		(layer "In2.Cu")
		(net "M_B_CPU0_SA_DQ<1>")
	)
	(segment
		(start 301.200566 -314.989718)
		(end 299.982382 -314.989718)
		(width 0.18288)
		(layer "In2.Cu")
		(net "M_B_CPU0_SA_DQ<1>")
	)
	(segment
		(start 337.229958 -277.508208)
		(end 337.230212 -277.522432)
		(width 0.088646)
		(layer "In2.Cu")
		(net "M_B_CPU0_SA_DQ<1>")
	)
	(segment
		(start 301.382176 -315.60516)
		(end 301.382176 -315.171328)
		(width 0.18288)
		(layer "In2.Cu")
		(net "M_B_CPU0_SA_DQ<1>")
	)
	(segment
		(start 333.079852 -281.48788)
		(end 332.160626 -282.407106)
		(width 0.18288)
		(layer "In2.Cu")
		(net "M_B_CPU0_SA_DQ<1>")
	)
	(segment
		(start 336.007964 -279.639776)
		(end 335.999074 -279.644856)
		(width 0.088646)
		(layer "In2.Cu")
		(net "M_B_CPU0_SA_DQ<1>")
	)
	(segment
		(start 306.933092 -315.861446)
		(end 306.311046 -315.861446)
		(width 0.18288)
		(layer "In2.Cu")
		(net "M_B_CPU0_SA_DQ<1>")
	)
	(segment
		(start 332.160626 -284.982666)
		(end 332.039468 -285.275274)
		(width 0.18288)
		(layer "In2.Cu")
		(net "M_B_CPU0_SA_DQ<1>")
	)
	(segment
		(start 333.512922 -281.48788)
		(end 333.28991 -281.48788)
		(width 0.088646)
		(layer "In2.Cu")
		(net "M_B_CPU0_SA_DQ<1>")
	)
	(segment
		(start 295.629076 -314.173616)
		(end 295.34739 -314.173616)
		(width 0.18288)
		(layer "In2.Cu")
		(net "M_B_CPU0_SA_DQ<1>")
	)
	(segment
		(start 336.947256 -278.012398)
		(end 336.938366 -278.017478)
		(width 0.088646)
		(layer "In2.Cu")
		(net "M_B_CPU0_SA_DQ<1>")
	)
	(segment
		(start 336.477864 -278.82596)
		(end 336.468974 -278.83104)
		(width 0.088646)
		(layer "In2.Cu")
		(net "M_B_CPU0_SA_DQ<1>")
	)
	(segment
		(start 322.431156 -306.568094)
		(end 314.566046 -314.433204)
		(width 0.18288)
		(layer "In2.Cu")
		(net "M_B_CPU0_SA_DQ<1>")
	)
	(segment
		(start 303.334166 -316.10808)
		(end 303.218088 -316.224158)
		(width 0.18288)
		(layer "In2.Cu")
		(net "M_B_CPU0_SA_DQ<1>")
	)
	(segment
		(start 336.47761 -278.826214)
		(end 336.477864 -278.82596)
		(width 0.088646)
		(layer "In2.Cu")
		(net "M_B_CPU0_SA_DQ<1>")
	)
	(segment
		(start 314.566046 -314.746132)
		(end 314.259214 -315.052964)
		(width 0.18288)
		(layer "In2.Cu")
		(net "M_B_CPU0_SA_DQ<1>")
	)
	(segment
		(start 336.759804 -278.336756)
		(end 336.759804 -278.346662)
		(width 0.088646)
		(layer "In2.Cu")
		(net "M_B_CPU0_SA_DQ<1>")
	)
	(segment
		(start 331.483208 -286.617918)
		(end 328.972672 -289.128454)
		(width 0.18288)
		(layer "In2.Cu")
		(net "M_B_CPU0_SA_DQ<1>")
	)
	(segment
		(start 302.436022 -316.224158)
		(end 302.010064 -315.7982)
		(width 0.18288)
		(layer "In2.Cu")
		(net "M_B_CPU0_SA_DQ<1>")
	)
	(segment
		(start 295.34739 -314.173616)
		(end 294.904414 -314.616592)
		(width 0.18288)
		(layer "In2.Cu")
		(net "M_B_CPU0_SA_DQ<1>")
	)
	(segment
		(start 306.156106 -316.016386)
		(end 304.688748 -316.016386)
		(width 0.18288)
		(layer "In2.Cu")
		(net "M_B_CPU0_SA_DQ<1>")
	)
	(segment
		(start 304.688748 -316.016386)
		(end 304.443638 -315.771276)
		(width 0.18288)
		(layer "In2.Cu")
		(net "M_B_CPU0_SA_DQ<1>")
	)
	(segment
		(start 298.16171 -314.19419)
		(end 297.8023 -314.5536)
		(width 0.18288)
		(layer "In2.Cu")
		(net "M_B_CPU0_SA_DQ<1>")
	)
	(segment
		(start 297.422062 -314.5536)
		(end 297.042078 -314.173616)
		(width 0.18288)
		(layer "In2.Cu")
		(net "M_B_CPU0_SA_DQ<1>")
	)
	(segment
		(start 297.8023 -314.5536)
		(end 297.422062 -314.5536)
		(width 0.18288)
		(layer "In2.Cu")
		(net "M_B_CPU0_SA_DQ<1>")
	)
	(segment
		(start 295.929558 -314.474098)
		(end 295.629076 -314.173616)
		(width 0.18288)
		(layer "In2.Cu")
		(net "M_B_CPU0_SA_DQ<1>")
	)
	(segment
		(start 335.820512 -279.964134)
		(end 335.820512 -279.982676)
		(width 0.088646)
		(layer "In2.Cu")
		(net "M_B_CPU0_SA_DQ<1>")
	)
	(segment
		(start 336.955384 -278.007572)
		(end 336.947256 -278.012398)
		(width 0.088646)
		(layer "In2.Cu")
		(net "M_B_CPU0_SA_DQ<1>")
	)
	(segment
		(start 333.28991 -281.48788)
		(end 333.079852 -281.48788)
		(width 0.18288)
		(layer "In2.Cu")
		(net "M_B_CPU0_SA_DQ<1>")
	)
	(segment
		(start 334.410812 -280.778204)
		(end 334.410812 -280.78811)
		(width 0.088646)
		(layer "In2.Cu")
		(net "M_B_CPU0_SA_DQ<1>")
	)
	(segment
		(start 304.443638 -315.771276)
		(end 303.49698 -315.771276)
		(width 0.18288)
		(layer "In2.Cu")
		(net "M_B_CPU0_SA_DQ<1>")
	)
	(segment
		(start 314.259214 -315.052964)
		(end 311.76087 -315.052964)
		(width 0.18288)
		(layer "In2.Cu")
		(net "M_B_CPU0_SA_DQ<1>")
	)
	(segment
		(start 310.911748 -315.902086)
		(end 308.097936 -315.902086)
		(width 0.18288)
		(layer "In2.Cu")
		(net "M_B_CPU0_SA_DQ<1>")
	)
	(segment
		(start 299.982382 -314.989718)
		(end 299.186854 -314.19419)
		(width 0.18288)
		(layer "In2.Cu")
		(net "M_B_CPU0_SA_DQ<1>")
	)
	(segment
		(start 302.010064 -315.7982)
		(end 301.575216 -315.7982)
		(width 0.18288)
		(layer "In2.Cu")
		(net "M_B_CPU0_SA_DQ<1>")
	)
	(segment
		(start 301.575216 -315.7982)
		(end 301.382176 -315.60516)
		(width 0.18288)
		(layer "In2.Cu")
		(net "M_B_CPU0_SA_DQ<1>")
	)
	(arc
		(start 336.290412 -279.160224)
		(mid 336.212301 -279.437173)
		(end 336.007964 -279.639776)
		(width 0.088646)
		(layer "In2.Cu")
		(net "M_B_CPU0_SA_DQ<1>")
	)
	(arc
		(start 334.410812 -280.78811)
		(mid 334.241827 -281.181374)
		(end 333.845662 -281.343354)
		(width 0.088646)
		(layer "In2.Cu")
		(net "M_B_CPU0_SA_DQ<1>")
	)
	(arc
		(start 336.468974 -278.83104)
		(mid 336.33806 -278.9674)
		(end 336.290412 -279.150318)
		(width 0.088646)
		(layer "In2.Cu")
		(net "M_B_CPU0_SA_DQ<1>")
	)
	(arc
		(start 334.97266 -280.453846)
		(mid 334.785462 -280.403703)
		(end 334.598264 -280.453846)
		(width 0.088646)
		(layer "In2.Cu")
		(net "M_B_CPU0_SA_DQ<1>")
	)
	(arc
		(start 335.538064 -280.453846)
		(mid 335.255362 -280.529588)
		(end 334.97266 -280.453846)
		(width 0.088646)
		(layer "In2.Cu")
		(net "M_B_CPU0_SA_DQ<1>")
	)
	(arc
		(start 336.947764 -277.032974)
		(mid 337.150824 -277.233783)
		(end 337.229958 -277.508208)
		(width 0.088646)
		(layer "In2.Cu")
		(net "M_B_CPU0_SA_DQ<1>")
	)
	(arc
		(start 337.230212 -277.522432)
		(mid 337.15681 -277.801282)
		(end 336.955384 -278.007572)
		(width 0.088646)
		(layer "In2.Cu")
		(net "M_B_CPU0_SA_DQ<1>")
	)
	(arc
		(start 336.938366 -278.017478)
		(mid 336.807452 -278.153838)
		(end 336.759804 -278.336756)
		(width 0.088646)
		(layer "In2.Cu")
		(net "M_B_CPU0_SA_DQ<1>")
	)
	(arc
		(start 334.589374 -280.458926)
		(mid 334.45846 -280.595286)
		(end 334.410812 -280.778204)
		(width 0.088646)
		(layer "In2.Cu")
		(net "M_B_CPU0_SA_DQ<1>")
	)
	(arc
		(start 336.760312 -276.708616)
		(mid 336.807991 -276.891516)
		(end 336.938874 -277.027894)
		(width 0.088646)
		(layer "In2.Cu")
		(net "M_B_CPU0_SA_DQ<1>")
	)
	(arc
		(start 336.759804 -278.346662)
		(mid 336.68177 -278.623548)
		(end 336.47761 -278.826214)
		(width 0.088646)
		(layer "In2.Cu")
		(net "M_B_CPU0_SA_DQ<1>")
	)
	(arc
		(start 335.820512 -279.982676)
		(mid 335.74035 -280.254865)
		(end 335.538064 -280.453846)
		(width 0.088646)
		(layer "In2.Cu")
		(net "M_B_CPU0_SA_DQ<1>")
	)
	(arc
		(start 335.999074 -279.644856)
		(mid 335.86816 -279.781216)
		(end 335.820512 -279.964134)
		(width 0.088646)
		(layer "In2.Cu")
		(net "M_B_CPU0_SA_DQ<1>")
	)
	(segment
		(start 295.693846 -295.342564)
		(end 295.544748 -295.491662)
		(width 0.20066)
		(layer "F.Cu")
		(net "M_B_CPU0_SA_DQ<19>")
	)
	(segment
		(start 295.000426 -295.491662)
		(end 292.927532 -295.491662)
		(width 0.1016)
		(layer "F.Cu")
		(net "M_B_CPU0_SA_DQ<19>")
	)
	(segment
		(start 297.899582 -295.06672)
		(end 297.08348 -295.06672)
		(width 0.20066)
		(layer "F.Cu")
		(net "M_B_CPU0_SA_DQ<19>")
	)
	(segment
		(start 292.178994 -295.363392)
		(end 292.178994 -295.192704)
		(width 0.20066)
		(layer "F.Cu")
		(net "M_B_CPU0_SA_DQ<19>")
	)
	(segment
		(start 338.544916 -265.592306)
		(end 338.544662 -265.592306)
		(width 0.20066)
		(layer "F.Cu")
		(net "M_B_CPU0_SA_DQ<19>")
	)
	(segment
		(start 296.875962 -295.274238)
		(end 296.42943 -295.274238)
		(width 0.20066)
		(layer "F.Cu")
		(net "M_B_CPU0_SA_DQ<19>")
	)
	(segment
		(start 296.217594 -295.062402)
		(end 295.82237 -295.062402)
		(width 0.20066)
		(layer "F.Cu")
		(net "M_B_CPU0_SA_DQ<19>")
	)
	(segment
		(start 338.544662 -265.592306)
		(end 338.544662 -266.128246)
		(width 0.20066)
		(layer "F.Cu")
		(net "M_B_CPU0_SA_DQ<19>")
	)
	(segment
		(start 292.178994 -295.192704)
		(end 292.05301 -295.06672)
		(width 0.20066)
		(layer "F.Cu")
		(net "M_B_CPU0_SA_DQ<19>")
	)
	(segment
		(start 295.544748 -295.491662)
		(end 295.000426 -295.491662)
		(width 0.20066)
		(layer "F.Cu")
		(net "M_B_CPU0_SA_DQ<19>")
	)
	(segment
		(start 295.82237 -295.062402)
		(end 295.693846 -295.190926)
		(width 0.20066)
		(layer "F.Cu")
		(net "M_B_CPU0_SA_DQ<19>")
	)
	(segment
		(start 295.693846 -295.190926)
		(end 295.693846 -295.342564)
		(width 0.20066)
		(layer "F.Cu")
		(net "M_B_CPU0_SA_DQ<19>")
	)
	(segment
		(start 292.67531 -295.505886)
		(end 292.321488 -295.505886)
		(width 0.20066)
		(layer "F.Cu")
		(net "M_B_CPU0_SA_DQ<19>")
	)
	(segment
		(start 292.689534 -295.491662)
		(end 292.67531 -295.505886)
		(width 0.101854)
		(layer "F.Cu")
		(net "M_B_CPU0_SA_DQ<19>")
	)
	(segment
		(start 297.08348 -295.06672)
		(end 296.875962 -295.274238)
		(width 0.20066)
		(layer "F.Cu")
		(net "M_B_CPU0_SA_DQ<19>")
	)
	(segment
		(start 292.321488 -295.505886)
		(end 292.178994 -295.363392)
		(width 0.20066)
		(layer "F.Cu")
		(net "M_B_CPU0_SA_DQ<19>")
	)
	(segment
		(start 292.05301 -295.06672)
		(end 290.355782 -295.06672)
		(width 0.20066)
		(layer "F.Cu")
		(net "M_B_CPU0_SA_DQ<19>")
	)
	(segment
		(start 299.029882 -295.06672)
		(end 297.899582 -295.06672)
		(width 0.20066)
		(layer "F.Cu")
		(net "M_B_CPU0_SA_DQ<19>")
	)
	(segment
		(start 296.42943 -295.274238)
		(end 296.217594 -295.062402)
		(width 0.20066)
		(layer "F.Cu")
		(net "M_B_CPU0_SA_DQ<19>")
	)
	(segment
		(start 292.927532 -295.491662)
		(end 292.689534 -295.491662)
		(width 0.101854)
		(layer "F.Cu")
		(net "M_B_CPU0_SA_DQ<19>")
	)
	(segment
		(start 307.90896 -289.608768)
		(end 307.90896 -290.253928)
		(width 0.18288)
		(layer "In2.Cu")
		(net "M_B_CPU0_SA_DQ<19>")
	)
	(segment
		(start 303.859946 -294.566594)
		(end 302.88103 -295.54551)
		(width 0.18288)
		(layer "In2.Cu")
		(net "M_B_CPU0_SA_DQ<19>")
	)
	(segment
		(start 313.556904 -286.49549)
		(end 312.61558 -286.49549)
		(width 0.18288)
		(layer "In2.Cu")
		(net "M_B_CPU0_SA_DQ<19>")
	)
	(segment
		(start 304.673254 -292.968172)
		(end 303.859946 -293.78148)
		(width 0.18288)
		(layer "In2.Cu")
		(net "M_B_CPU0_SA_DQ<19>")
	)
	(segment
		(start 308.735222 -291.24402)
		(end 307.663596 -291.24402)
		(width 0.18288)
		(layer "In2.Cu")
		(net "M_B_CPU0_SA_DQ<19>")
	)
	(segment
		(start 311.42559 -287.02127)
		(end 309.552086 -288.894774)
		(width 0.18288)
		(layer "In2.Cu")
		(net "M_B_CPU0_SA_DQ<19>")
	)
	(segment
		(start 338.144866 -266.119102)
		(end 337.892136 -265.866372)
		(width 0.088646)
		(layer "In2.Cu")
		(net "M_B_CPU0_SA_DQ<19>")
	)
	(segment
		(start 307.055774 -292.968172)
		(end 304.673254 -292.968172)
		(width 0.18288)
		(layer "In2.Cu")
		(net "M_B_CPU0_SA_DQ<19>")
	)
	(segment
		(start 303.859946 -293.78148)
		(end 303.859946 -294.566594)
		(width 0.18288)
		(layer "In2.Cu")
		(net "M_B_CPU0_SA_DQ<19>")
	)
	(segment
		(start 308.896766 -291.082476)
		(end 308.735222 -291.24402)
		(width 0.18288)
		(layer "In2.Cu")
		(net "M_B_CPU0_SA_DQ<19>")
	)
	(segment
		(start 302.88103 -295.54551)
		(end 299.508672 -295.54551)
		(width 0.18288)
		(layer "In2.Cu")
		(net "M_B_CPU0_SA_DQ<19>")
	)
	(segment
		(start 328.59599 -269.499334)
		(end 325.726806 -272.368518)
		(width 0.18288)
		(layer "In2.Cu")
		(net "M_B_CPU0_SA_DQ<19>")
	)
	(segment
		(start 319.19037 -280.592784)
		(end 314.01639 -285.766764)
		(width 0.18288)
		(layer "In2.Cu")
		(net "M_B_CPU0_SA_DQ<19>")
	)
	(segment
		(start 338.544662 -266.128246)
		(end 338.167218 -266.128246)
		(width 0.088646)
		(layer "In2.Cu")
		(net "M_B_CPU0_SA_DQ<19>")
	)
	(segment
		(start 307.663596 -291.24402)
		(end 307.249068 -291.658548)
		(width 0.18288)
		(layer "In2.Cu")
		(net "M_B_CPU0_SA_DQ<19>")
	)
	(segment
		(start 328.86142 -269.389352)
		(end 328.59599 -269.499334)
		(width 0.18288)
		(layer "In2.Cu")
		(net "M_B_CPU0_SA_DQ<19>")
	)
	(segment
		(start 308.83733 -289.240722)
		(end 308.277006 -289.240722)
		(width 0.18288)
		(layer "In2.Cu")
		(net "M_B_CPU0_SA_DQ<19>")
	)
	(segment
		(start 332.435708 -266.376404)
		(end 331.874368 -266.376404)
		(width 0.088646)
		(layer "In2.Cu")
		(net "M_B_CPU0_SA_DQ<19>")
	)
	(segment
		(start 312.61558 -286.49549)
		(end 312.0898 -287.02127)
		(width 0.18288)
		(layer "In2.Cu")
		(net "M_B_CPU0_SA_DQ<19>")
	)
	(segment
		(start 336.244184 -265.877548)
		(end 336.203544 -265.899138)
		(width 0.088646)
		(layer "In2.Cu")
		(net "M_B_CPU0_SA_DQ<19>")
	)
	(segment
		(start 309.404258 -289.506152)
		(end 309.10276 -289.506152)
		(width 0.18288)
		(layer "In2.Cu")
		(net "M_B_CPU0_SA_DQ<19>")
	)
	(segment
		(start 319.19037 -279.17902)
		(end 319.19037 -280.592784)
		(width 0.18288)
		(layer "In2.Cu")
		(net "M_B_CPU0_SA_DQ<19>")
	)
	(segment
		(start 307.249068 -291.658548)
		(end 307.249068 -292.774878)
		(width 0.18288)
		(layer "In2.Cu")
		(net "M_B_CPU0_SA_DQ<19>")
	)
	(segment
		(start 314.01639 -285.766764)
		(end 314.01639 -286.036004)
		(width 0.18288)
		(layer "In2.Cu")
		(net "M_B_CPU0_SA_DQ<19>")
	)
	(segment
		(start 307.90896 -290.253928)
		(end 308.154832 -290.4998)
		(width 0.18288)
		(layer "In2.Cu")
		(net "M_B_CPU0_SA_DQ<19>")
	)
	(segment
		(start 314.01639 -286.036004)
		(end 313.556904 -286.49549)
		(width 0.18288)
		(layer "In2.Cu")
		(net "M_B_CPU0_SA_DQ<19>")
	)
	(segment
		(start 308.277006 -289.240722)
		(end 307.90896 -289.608768)
		(width 0.18288)
		(layer "In2.Cu")
		(net "M_B_CPU0_SA_DQ<19>")
	)
	(segment
		(start 308.643274 -290.4998)
		(end 308.896766 -290.753292)
		(width 0.18288)
		(layer "In2.Cu")
		(net "M_B_CPU0_SA_DQ<19>")
	)
	(segment
		(start 335.926684 -266.444222)
		(end 335.91246 -266.45235)
		(width 0.088646)
		(layer "In2.Cu")
		(net "M_B_CPU0_SA_DQ<19>")
	)
	(segment
		(start 307.249068 -292.774878)
		(end 307.055774 -292.968172)
		(width 0.18288)
		(layer "In2.Cu")
		(net "M_B_CPU0_SA_DQ<19>")
	)
	(segment
		(start 330.913232 -267.33754)
		(end 328.86142 -269.389352)
		(width 0.18288)
		(layer "In2.Cu")
		(net "M_B_CPU0_SA_DQ<19>")
	)
	(segment
		(start 325.726806 -272.368518)
		(end 325.726806 -272.642584)
		(width 0.18288)
		(layer "In2.Cu")
		(net "M_B_CPU0_SA_DQ<19>")
	)
	(segment
		(start 309.552086 -289.358324)
		(end 309.404258 -289.506152)
		(width 0.18288)
		(layer "In2.Cu")
		(net "M_B_CPU0_SA_DQ<19>")
	)
	(segment
		(start 325.726806 -272.642584)
		(end 319.19037 -279.17902)
		(width 0.18288)
		(layer "In2.Cu")
		(net "M_B_CPU0_SA_DQ<19>")
	)
	(segment
		(start 299.508672 -295.54551)
		(end 299.029882 -295.06672)
		(width 0.18288)
		(layer "In2.Cu")
		(net "M_B_CPU0_SA_DQ<19>")
	)
	(segment
		(start 308.896766 -290.753292)
		(end 308.896766 -291.082476)
		(width 0.18288)
		(layer "In2.Cu")
		(net "M_B_CPU0_SA_DQ<19>")
	)
	(segment
		(start 308.154832 -290.4998)
		(end 308.643274 -290.4998)
		(width 0.18288)
		(layer "In2.Cu")
		(net "M_B_CPU0_SA_DQ<19>")
	)
	(segment
		(start 309.552086 -288.894774)
		(end 309.552086 -289.358324)
		(width 0.18288)
		(layer "In2.Cu")
		(net "M_B_CPU0_SA_DQ<19>")
	)
	(segment
		(start 331.874368 -266.376404)
		(end 330.913232 -267.33754)
		(width 0.088646)
		(layer "In2.Cu")
		(net "M_B_CPU0_SA_DQ<19>")
	)
	(segment
		(start 309.10276 -289.506152)
		(end 308.83733 -289.240722)
		(width 0.18288)
		(layer "In2.Cu")
		(net "M_B_CPU0_SA_DQ<19>")
	)
	(segment
		(start 312.0898 -287.02127)
		(end 311.42559 -287.02127)
		(width 0.18288)
		(layer "In2.Cu")
		(net "M_B_CPU0_SA_DQ<19>")
	)
	(arc
		(start 333.658464 -266.45235)
		(mid 333.375762 -266.376574)
		(end 333.09306 -266.45235)
		(width 0.088646)
		(layer "In2.Cu")
		(net "M_B_CPU0_SA_DQ<19>")
	)
	(arc
		(start 334.03286 -266.45235)
		(mid 333.845662 -266.502527)
		(end 333.658464 -266.45235)
		(width 0.088646)
		(layer "In2.Cu")
		(net "M_B_CPU0_SA_DQ<19>")
	)
	(arc
		(start 336.477864 -265.803888)
		(mid 336.365057 -265.853503)
		(end 336.244184 -265.877548)
		(width 0.088646)
		(layer "In2.Cu")
		(net "M_B_CPU0_SA_DQ<19>")
	)
	(arc
		(start 334.598264 -266.45235)
		(mid 334.315562 -266.376574)
		(end 334.03286 -266.45235)
		(width 0.088646)
		(layer "In2.Cu")
		(net "M_B_CPU0_SA_DQ<19>")
	)
	(arc
		(start 336.203544 -265.899138)
		(mid 336.127021 -266.002517)
		(end 336.099912 -266.128246)
		(width 0.088646)
		(layer "In2.Cu")
		(net "M_B_CPU0_SA_DQ<19>")
	)
	(arc
		(start 335.538064 -266.45235)
		(mid 335.255362 -266.376574)
		(end 334.97266 -266.45235)
		(width 0.088646)
		(layer "In2.Cu")
		(net "M_B_CPU0_SA_DQ<19>")
	)
	(arc
		(start 335.91246 -266.45235)
		(mid 335.725262 -266.502527)
		(end 335.538064 -266.45235)
		(width 0.088646)
		(layer "In2.Cu")
		(net "M_B_CPU0_SA_DQ<19>")
	)
	(arc
		(start 332.718664 -266.45235)
		(mid 332.582192 -266.395727)
		(end 332.435708 -266.376404)
		(width 0.088646)
		(layer "In2.Cu")
		(net "M_B_CPU0_SA_DQ<19>")
	)
	(arc
		(start 337.417664 -265.803888)
		(mid 337.134962 -265.87963)
		(end 336.85226 -265.803888)
		(width 0.088646)
		(layer "In2.Cu")
		(net "M_B_CPU0_SA_DQ<19>")
	)
	(arc
		(start 333.09306 -266.45235)
		(mid 332.905862 -266.502527)
		(end 332.718664 -266.45235)
		(width 0.088646)
		(layer "In2.Cu")
		(net "M_B_CPU0_SA_DQ<19>")
	)
	(arc
		(start 336.85226 -265.803888)
		(mid 336.665062 -265.753745)
		(end 336.477864 -265.803888)
		(width 0.088646)
		(layer "In2.Cu")
		(net "M_B_CPU0_SA_DQ<19>")
	)
	(arc
		(start 334.97266 -266.45235)
		(mid 334.785462 -266.502527)
		(end 334.598264 -266.45235)
		(width 0.088646)
		(layer "In2.Cu")
		(net "M_B_CPU0_SA_DQ<19>")
	)
	(arc
		(start 336.099912 -266.128246)
		(mid 336.053773 -266.308431)
		(end 335.926684 -266.444222)
		(width 0.088646)
		(layer "In2.Cu")
		(net "M_B_CPU0_SA_DQ<19>")
	)
	(arc
		(start 338.167218 -266.128246)
		(mid 338.155165 -266.125849)
		(end 338.144866 -266.119102)
		(width 0.088646)
		(layer "In2.Cu")
		(net "M_B_CPU0_SA_DQ<19>")
	)
	(arc
		(start 337.892136 -265.866372)
		(mid 337.665513 -265.754701)
		(end 337.417664 -265.803888)
		(width 0.088646)
		(layer "In2.Cu")
		(net "M_B_CPU0_SA_DQ<19>")
	)
	(segment
		(start 291.502846 -296.766742)
		(end 290.355782 -296.766742)
		(width 0.20066)
		(layer "F.Cu")
		(net "M_B_CPU0_SA_DQ<18>")
	)
	(segment
		(start 292.67531 -296.33164)
		(end 291.937948 -296.33164)
		(width 0.20066)
		(layer "F.Cu")
		(net "M_B_CPU0_SA_DQ<18>")
	)
	(segment
		(start 295.633394 -296.3418)
		(end 295.000426 -296.3418)
		(width 0.20066)
		(layer "F.Cu")
		(net "M_B_CPU0_SA_DQ<18>")
	)
	(segment
		(start 292.940486 -296.3418)
		(end 292.68547 -296.3418)
		(width 0.101854)
		(layer "F.Cu")
		(net "M_B_CPU0_SA_DQ<18>")
	)
	(segment
		(start 297.899582 -296.766742)
		(end 296.584878 -296.766742)
		(width 0.20066)
		(layer "F.Cu")
		(net "M_B_CPU0_SA_DQ<18>")
	)
	(segment
		(start 295.777158 -296.811192)
		(end 295.777158 -296.485564)
		(width 0.20066)
		(layer "F.Cu")
		(net "M_B_CPU0_SA_DQ<18>")
	)
	(segment
		(start 292.68547 -296.3418)
		(end 292.67531 -296.33164)
		(width 0.101854)
		(layer "F.Cu")
		(net "M_B_CPU0_SA_DQ<18>")
	)
	(segment
		(start 295.777158 -296.485564)
		(end 295.633394 -296.3418)
		(width 0.20066)
		(layer "F.Cu")
		(net "M_B_CPU0_SA_DQ<18>")
	)
	(segment
		(start 291.937948 -296.33164)
		(end 291.502846 -296.766742)
		(width 0.20066)
		(layer "F.Cu")
		(net "M_B_CPU0_SA_DQ<18>")
	)
	(segment
		(start 296.584878 -296.766742)
		(end 296.373042 -296.978578)
		(width 0.20066)
		(layer "F.Cu")
		(net "M_B_CPU0_SA_DQ<18>")
	)
	(segment
		(start 296.373042 -296.978578)
		(end 295.944544 -296.978578)
		(width 0.20066)
		(layer "F.Cu")
		(net "M_B_CPU0_SA_DQ<18>")
	)
	(segment
		(start 295.944544 -296.978578)
		(end 295.777158 -296.811192)
		(width 0.20066)
		(layer "F.Cu")
		(net "M_B_CPU0_SA_DQ<18>")
	)
	(segment
		(start 299.029882 -296.766742)
		(end 297.899582 -296.766742)
		(width 0.20066)
		(layer "F.Cu")
		(net "M_B_CPU0_SA_DQ<18>")
	)
	(segment
		(start 338.074762 -266.405868)
		(end 338.074762 -266.941808)
		(width 0.20066)
		(layer "F.Cu")
		(net "M_B_CPU0_SA_DQ<18>")
	)
	(segment
		(start 295.000426 -296.3418)
		(end 292.940486 -296.3418)
		(width 0.1016)
		(layer "F.Cu")
		(net "M_B_CPU0_SA_DQ<18>")
	)
	(segment
		(start 315.058044 -286.17291)
		(end 315.058044 -287.211008)
		(width 0.18288)
		(layer "In2.Cu")
		(net "M_B_CPU0_SA_DQ<18>")
	)
	(segment
		(start 305.89728 -296.060876)
		(end 305.62423 -296.060876)
		(width 0.18288)
		(layer "In2.Cu")
		(net "M_B_CPU0_SA_DQ<18>")
	)
	(segment
		(start 310.439562 -292.695376)
		(end 309.84317 -293.291768)
		(width 0.18288)
		(layer "In2.Cu")
		(net "M_B_CPU0_SA_DQ<18>")
	)
	(segment
		(start 300.253908 -297.46956)
		(end 299.7327 -297.46956)
		(width 0.18288)
		(layer "In2.Cu")
		(net "M_B_CPU0_SA_DQ<18>")
	)
	(segment
		(start 314.511436 -288.531046)
		(end 314.201048 -288.73831)
		(width 0.18288)
		(layer "In2.Cu")
		(net "M_B_CPU0_SA_DQ<18>")
	)
	(segment
		(start 337.761834 -266.941808)
		(end 337.696556 -266.87653)
		(width 0.088646)
		(layer "In2.Cu")
		(net "M_B_CPU0_SA_DQ<18>")
	)
	(segment
		(start 314.201048 -288.73831)
		(end 312.01741 -288.73831)
		(width 0.18288)
		(layer "In2.Cu")
		(net "M_B_CPU0_SA_DQ<18>")
	)
	(segment
		(start 307.08981 -295.348406)
		(end 306.309776 -295.348406)
		(width 0.18288)
		(layer "In2.Cu")
		(net "M_B_CPU0_SA_DQ<18>")
	)
	(segment
		(start 299.7327 -297.46956)
		(end 299.029882 -296.766742)
		(width 0.18288)
		(layer "In2.Cu")
		(net "M_B_CPU0_SA_DQ<18>")
	)
	(segment
		(start 305.244754 -295.6814)
		(end 304.97145 -295.6814)
		(width 0.18288)
		(layer "In2.Cu")
		(net "M_B_CPU0_SA_DQ<18>")
	)
	(segment
		(start 306.309776 -295.348406)
		(end 306.110894 -295.547288)
		(width 0.18288)
		(layer "In2.Cu")
		(net "M_B_CPU0_SA_DQ<18>")
	)
	(segment
		(start 304.97145 -295.6814)
		(end 304.774092 -295.878758)
		(width 0.18288)
		(layer "In2.Cu")
		(net "M_B_CPU0_SA_DQ<18>")
	)
	(segment
		(start 309.84317 -293.577772)
		(end 309.62219 -293.798752)
		(width 0.18288)
		(layer "In2.Cu")
		(net "M_B_CPU0_SA_DQ<18>")
	)
	(segment
		(start 336.39125 -267.261086)
		(end 336.38236 -267.266166)
		(width 0.088646)
		(layer "In2.Cu")
		(net "M_B_CPU0_SA_DQ<18>")
	)
	(segment
		(start 326.595994 -273.210528)
		(end 320.20637 -279.600152)
		(width 0.18288)
		(layer "In2.Cu")
		(net "M_B_CPU0_SA_DQ<18>")
	)
	(segment
		(start 307.283104 -294.438578)
		(end 307.283104 -295.155112)
		(width 0.18288)
		(layer "In2.Cu")
		(net "M_B_CPU0_SA_DQ<18>")
	)
	(segment
		(start 300.785022 -296.938446)
		(end 300.253908 -297.46956)
		(width 0.18288)
		(layer "In2.Cu")
		(net "M_B_CPU0_SA_DQ<18>")
	)
	(segment
		(start 312.01741 -288.73831)
		(end 310.439562 -290.316158)
		(width 0.18288)
		(layer "In2.Cu")
		(net "M_B_CPU0_SA_DQ<18>")
	)
	(segment
		(start 326.595994 -272.63217)
		(end 326.595994 -273.210528)
		(width 0.18288)
		(layer "In2.Cu")
		(net "M_B_CPU0_SA_DQ<18>")
	)
	(segment
		(start 309.62219 -293.798752)
		(end 307.92293 -293.798752)
		(width 0.18288)
		(layer "In2.Cu")
		(net "M_B_CPU0_SA_DQ<18>")
	)
	(segment
		(start 304.774092 -296.267378)
		(end 304.473356 -296.568114)
		(width 0.18288)
		(layer "In2.Cu")
		(net "M_B_CPU0_SA_DQ<18>")
	)
	(segment
		(start 331.401928 -267.826236)
		(end 326.595994 -272.63217)
		(width 0.18288)
		(layer "In2.Cu")
		(net "M_B_CPU0_SA_DQ<18>")
	)
	(segment
		(start 305.62423 -296.060876)
		(end 305.244754 -295.6814)
		(width 0.18288)
		(layer "In2.Cu")
		(net "M_B_CPU0_SA_DQ<18>")
	)
	(segment
		(start 306.110894 -295.547288)
		(end 306.110894 -295.847262)
		(width 0.18288)
		(layer "In2.Cu")
		(net "M_B_CPU0_SA_DQ<18>")
	)
	(segment
		(start 320.20637 -279.600152)
		(end 320.20637 -281.024584)
		(width 0.18288)
		(layer "In2.Cu")
		(net "M_B_CPU0_SA_DQ<18>")
	)
	(segment
		(start 303.328578 -296.568114)
		(end 302.663098 -297.233594)
		(width 0.18288)
		(layer "In2.Cu")
		(net "M_B_CPU0_SA_DQ<18>")
	)
	(segment
		(start 320.20637 -281.024584)
		(end 315.058044 -286.17291)
		(width 0.18288)
		(layer "In2.Cu")
		(net "M_B_CPU0_SA_DQ<18>")
	)
	(segment
		(start 315.058044 -287.211008)
		(end 314.511436 -288.531046)
		(width 0.18288)
		(layer "In2.Cu")
		(net "M_B_CPU0_SA_DQ<18>")
	)
	(segment
		(start 336.569812 -266.931902)
		(end 336.569812 -266.941808)
		(width 0.088646)
		(layer "In2.Cu")
		(net "M_B_CPU0_SA_DQ<18>")
	)
	(segment
		(start 304.473356 -296.568114)
		(end 303.328578 -296.568114)
		(width 0.18288)
		(layer "In2.Cu")
		(net "M_B_CPU0_SA_DQ<18>")
	)
	(segment
		(start 301.955962 -296.938446)
		(end 300.785022 -296.938446)
		(width 0.18288)
		(layer "In2.Cu")
		(net "M_B_CPU0_SA_DQ<18>")
	)
	(segment
		(start 304.774092 -295.878758)
		(end 304.774092 -296.267378)
		(width 0.18288)
		(layer "In2.Cu")
		(net "M_B_CPU0_SA_DQ<18>")
	)
	(segment
		(start 302.25111 -297.233594)
		(end 301.955962 -296.938446)
		(width 0.18288)
		(layer "In2.Cu")
		(net "M_B_CPU0_SA_DQ<18>")
	)
	(segment
		(start 310.439562 -290.316158)
		(end 310.439562 -292.695376)
		(width 0.18288)
		(layer "In2.Cu")
		(net "M_B_CPU0_SA_DQ<18>")
	)
	(segment
		(start 332.435962 -267.316966)
		(end 331.911198 -267.316966)
		(width 0.088646)
		(layer "In2.Cu")
		(net "M_B_CPU0_SA_DQ<18>")
	)
	(segment
		(start 331.911198 -267.316966)
		(end 331.401928 -267.826236)
		(width 0.088646)
		(layer "In2.Cu")
		(net "M_B_CPU0_SA_DQ<18>")
	)
	(segment
		(start 302.663098 -297.233594)
		(end 302.25111 -297.233594)
		(width 0.18288)
		(layer "In2.Cu")
		(net "M_B_CPU0_SA_DQ<18>")
	)
	(segment
		(start 338.074762 -266.941808)
		(end 337.761834 -266.941808)
		(width 0.088646)
		(layer "In2.Cu")
		(net "M_B_CPU0_SA_DQ<18>")
	)
	(segment
		(start 307.92293 -293.798752)
		(end 307.283104 -294.438578)
		(width 0.18288)
		(layer "In2.Cu")
		(net "M_B_CPU0_SA_DQ<18>")
	)
	(segment
		(start 306.110894 -295.847262)
		(end 305.89728 -296.060876)
		(width 0.18288)
		(layer "In2.Cu")
		(net "M_B_CPU0_SA_DQ<18>")
	)
	(segment
		(start 307.283104 -295.155112)
		(end 307.08981 -295.348406)
		(width 0.18288)
		(layer "In2.Cu")
		(net "M_B_CPU0_SA_DQ<18>")
	)
	(segment
		(start 309.84317 -293.291768)
		(end 309.84317 -293.577772)
		(width 0.18288)
		(layer "In2.Cu")
		(net "M_B_CPU0_SA_DQ<18>")
	)
	(arc
		(start 336.85226 -266.45235)
		(mid 336.647925 -266.654955)
		(end 336.569812 -266.931902)
		(width 0.088646)
		(layer "In2.Cu")
		(net "M_B_CPU0_SA_DQ<18>")
	)
	(arc
		(start 336.569812 -266.941808)
		(mid 336.522133 -267.124708)
		(end 336.39125 -267.261086)
		(width 0.088646)
		(layer "In2.Cu")
		(net "M_B_CPU0_SA_DQ<18>")
	)
	(arc
		(start 336.007964 -267.266166)
		(mid 335.725262 -267.190424)
		(end 335.44256 -267.266166)
		(width 0.088646)
		(layer "In2.Cu")
		(net "M_B_CPU0_SA_DQ<18>")
	)
	(arc
		(start 336.38236 -267.266166)
		(mid 336.195162 -267.316309)
		(end 336.007964 -267.266166)
		(width 0.088646)
		(layer "In2.Cu")
		(net "M_B_CPU0_SA_DQ<18>")
	)
	(arc
		(start 337.417664 -266.45235)
		(mid 337.134962 -266.376574)
		(end 336.85226 -266.45235)
		(width 0.088646)
		(layer "In2.Cu")
		(net "M_B_CPU0_SA_DQ<18>")
	)
	(arc
		(start 333.188564 -267.266166)
		(mid 332.905862 -267.190424)
		(end 332.62316 -267.266166)
		(width 0.088646)
		(layer "In2.Cu")
		(net "M_B_CPU0_SA_DQ<18>")
	)
	(arc
		(start 332.62316 -267.266166)
		(mid 332.532899 -267.303863)
		(end 332.435962 -267.316966)
		(width 0.088646)
		(layer "In2.Cu")
		(net "M_B_CPU0_SA_DQ<18>")
	)
	(arc
		(start 333.56296 -267.266166)
		(mid 333.375762 -267.316309)
		(end 333.188564 -267.266166)
		(width 0.088646)
		(layer "In2.Cu")
		(net "M_B_CPU0_SA_DQ<18>")
	)
	(arc
		(start 334.128364 -267.266166)
		(mid 333.845662 -267.190424)
		(end 333.56296 -267.266166)
		(width 0.088646)
		(layer "In2.Cu")
		(net "M_B_CPU0_SA_DQ<18>")
	)
	(arc
		(start 337.696556 -266.87653)
		(mid 337.607427 -266.631355)
		(end 337.417664 -266.45235)
		(width 0.088646)
		(layer "In2.Cu")
		(net "M_B_CPU0_SA_DQ<18>")
	)
	(arc
		(start 335.068164 -267.266166)
		(mid 334.785462 -267.190424)
		(end 334.50276 -267.266166)
		(width 0.088646)
		(layer "In2.Cu")
		(net "M_B_CPU0_SA_DQ<18>")
	)
	(arc
		(start 335.44256 -267.266166)
		(mid 335.255362 -267.316309)
		(end 335.068164 -267.266166)
		(width 0.088646)
		(layer "In2.Cu")
		(net "M_B_CPU0_SA_DQ<18>")
	)
	(arc
		(start 334.50276 -267.266166)
		(mid 334.315562 -267.316309)
		(end 334.128364 -267.266166)
		(width 0.088646)
		(layer "In2.Cu")
		(net "M_B_CPU0_SA_DQ<18>")
	)
	(segment
		(start 288.305748 -296.127932)
		(end 287.801304 -296.127932)
		(width 0.20066)
		(layer "F.Cu")
		(net "M_B_CPU0_SA_DQ<17>")
	)
	(segment
		(start 288.46018 -295.645332)
		(end 288.46018 -295.9735)
		(width 0.20066)
		(layer "F.Cu")
		(net "M_B_CPU0_SA_DQ<17>")
	)
	(segment
		(start 289.240468 -295.491662)
		(end 289.231578 -295.482772)
		(width 0.1016)
		(layer "F.Cu")
		(net "M_B_CPU0_SA_DQ<17>")
	)
	(segment
		(start 287.589976 -295.916604)
		(end 286.255714 -295.916604)
		(width 0.20066)
		(layer "F.Cu")
		(net "M_B_CPU0_SA_DQ<17>")
	)
	(segment
		(start 293.799514 -295.916604)
		(end 292.160198 -295.916604)
		(width 0.20066)
		(layer "F.Cu")
		(net "M_B_CPU0_SA_DQ<17>")
	)
	(segment
		(start 291.225986 -295.491662)
		(end 289.240468 -295.491662)
		(width 0.1016)
		(layer "F.Cu")
		(net "M_B_CPU0_SA_DQ<17>")
	)
	(segment
		(start 287.801304 -296.127932)
		(end 287.589976 -295.916604)
		(width 0.20066)
		(layer "F.Cu")
		(net "M_B_CPU0_SA_DQ<17>")
	)
	(segment
		(start 291.556694 -295.491662)
		(end 291.225986 -295.491662)
		(width 0.101854)
		(layer "F.Cu")
		(net "M_B_CPU0_SA_DQ<17>")
	)
	(segment
		(start 336.665062 -265.592306)
		(end 336.665062 -266.128246)
		(width 0.20066)
		(layer "F.Cu")
		(net "M_B_CPU0_SA_DQ<17>")
	)
	(segment
		(start 294.904414 -295.916604)
		(end 293.799514 -295.916604)
		(width 0.20066)
		(layer "F.Cu")
		(net "M_B_CPU0_SA_DQ<17>")
	)
	(segment
		(start 288.62274 -295.482772)
		(end 288.46018 -295.645332)
		(width 0.20066)
		(layer "F.Cu")
		(net "M_B_CPU0_SA_DQ<17>")
	)
	(segment
		(start 291.735256 -295.491662)
		(end 291.556694 -295.491662)
		(width 0.20066)
		(layer "F.Cu")
		(net "M_B_CPU0_SA_DQ<17>")
	)
	(segment
		(start 288.46018 -295.9735)
		(end 288.305748 -296.127932)
		(width 0.20066)
		(layer "F.Cu")
		(net "M_B_CPU0_SA_DQ<17>")
	)
	(segment
		(start 336.665316 -265.592306)
		(end 336.665062 -265.592306)
		(width 0.20066)
		(layer "F.Cu")
		(net "M_B_CPU0_SA_DQ<17>")
	)
	(segment
		(start 289.231578 -295.482772)
		(end 288.62274 -295.482772)
		(width 0.20066)
		(layer "F.Cu")
		(net "M_B_CPU0_SA_DQ<17>")
	)
	(segment
		(start 292.160198 -295.916604)
		(end 291.735256 -295.491662)
		(width 0.20066)
		(layer "F.Cu")
		(net "M_B_CPU0_SA_DQ<17>")
	)
	(segment
		(start 305.514502 -294.60571)
		(end 304.590958 -294.60571)
		(width 0.18288)
		(layer "In2.Cu")
		(net "M_B_CPU0_SA_DQ<17>")
	)
	(segment
		(start 311.559956 -287.801558)
		(end 310.485282 -288.876232)
		(width 0.18288)
		(layer "In2.Cu")
		(net "M_B_CPU0_SA_DQ<17>")
	)
	(segment
		(start 332.435708 -266.56665)
		(end 332.172818 -266.56665)
		(width 0.088646)
		(layer "In2.Cu")
		(net "M_B_CPU0_SA_DQ<17>")
	)
	(segment
		(start 303.092358 -296.10431)
		(end 302.381158 -296.10431)
		(width 0.18288)
		(layer "In2.Cu")
		(net "M_B_CPU0_SA_DQ<17>")
	)
	(segment
		(start 300.476412 -296.323004)
		(end 300.339506 -296.186098)
		(width 0.18288)
		(layer "In2.Cu")
		(net "M_B_CPU0_SA_DQ<17>")
	)
	(segment
		(start 309.929276 -291.460428)
		(end 309.929276 -291.86378)
		(width 0.18288)
		(layer "In2.Cu")
		(net "M_B_CPU0_SA_DQ<17>")
	)
	(segment
		(start 332.172818 -266.56665)
		(end 331.15758 -267.581888)
		(width 0.088646)
		(layer "In2.Cu")
		(net "M_B_CPU0_SA_DQ<17>")
	)
	(segment
		(start 310.485282 -289.54476)
		(end 309.503826 -290.526216)
		(width 0.18288)
		(layer "In2.Cu")
		(net "M_B_CPU0_SA_DQ<17>")
	)
	(segment
		(start 314.548266 -285.956502)
		(end 314.548266 -287.079944)
		(width 0.18288)
		(layer "In2.Cu")
		(net "M_B_CPU0_SA_DQ<17>")
	)
	(segment
		(start 336.665062 -266.128246)
		(end 336.169762 -266.477242)
		(width 0.088646)
		(layer "In2.Cu")
		(net "M_B_CPU0_SA_DQ<17>")
	)
	(segment
		(start 298.656248 -296.281094)
		(end 297.110404 -296.281094)
		(width 0.18288)
		(layer "In2.Cu")
		(net "M_B_CPU0_SA_DQ<17>")
	)
	(segment
		(start 319.69837 -280.806398)
		(end 314.548266 -285.956502)
		(width 0.18288)
		(layer "In2.Cu")
		(net "M_B_CPU0_SA_DQ<17>")
	)
	(segment
		(start 308.516274 -292.453822)
		(end 307.265324 -293.704772)
		(width 0.18288)
		(layer "In2.Cu")
		(net "M_B_CPU0_SA_DQ<17>")
	)
	(segment
		(start 326.203818 -272.884138)
		(end 319.69837 -279.389586)
		(width 0.18288)
		(layer "In2.Cu")
		(net "M_B_CPU0_SA_DQ<17>")
	)
	(segment
		(start 300.339506 -296.186098)
		(end 299.464984 -296.186098)
		(width 0.18288)
		(layer "In2.Cu")
		(net "M_B_CPU0_SA_DQ<17>")
	)
	(segment
		(start 307.265324 -293.704772)
		(end 306.41544 -293.704772)
		(width 0.18288)
		(layer "In2.Cu")
		(net "M_B_CPU0_SA_DQ<17>")
	)
	(segment
		(start 314.548266 -287.079944)
		(end 313.826652 -287.801558)
		(width 0.18288)
		(layer "In2.Cu")
		(net "M_B_CPU0_SA_DQ<17>")
	)
	(segment
		(start 326.203818 -272.53565)
		(end 326.203818 -272.884138)
		(width 0.18288)
		(layer "In2.Cu")
		(net "M_B_CPU0_SA_DQ<17>")
	)
	(segment
		(start 297.110404 -296.281094)
		(end 296.82948 -296.562018)
		(width 0.18288)
		(layer "In2.Cu")
		(net "M_B_CPU0_SA_DQ<17>")
	)
	(segment
		(start 309.503826 -290.526216)
		(end 309.503826 -291.034978)
		(width 0.18288)
		(layer "In2.Cu")
		(net "M_B_CPU0_SA_DQ<17>")
	)
	(segment
		(start 331.15758 -267.581888)
		(end 326.203818 -272.53565)
		(width 0.18288)
		(layer "In2.Cu")
		(net "M_B_CPU0_SA_DQ<17>")
	)
	(segment
		(start 309.677816 -292.11524)
		(end 308.659784 -292.11524)
		(width 0.18288)
		(layer "In2.Cu")
		(net "M_B_CPU0_SA_DQ<17>")
	)
	(segment
		(start 319.69837 -279.389586)
		(end 319.69837 -280.806398)
		(width 0.18288)
		(layer "In2.Cu")
		(net "M_B_CPU0_SA_DQ<17>")
	)
	(segment
		(start 302.381158 -296.10431)
		(end 302.162464 -296.323004)
		(width 0.18288)
		(layer "In2.Cu")
		(net "M_B_CPU0_SA_DQ<17>")
	)
	(segment
		(start 308.516274 -292.25875)
		(end 308.516274 -292.453822)
		(width 0.18288)
		(layer "In2.Cu")
		(net "M_B_CPU0_SA_DQ<17>")
	)
	(segment
		(start 306.41544 -293.704772)
		(end 305.514502 -294.60571)
		(width 0.18288)
		(layer "In2.Cu")
		(net "M_B_CPU0_SA_DQ<17>")
	)
	(segment
		(start 299.309282 -296.3418)
		(end 298.716954 -296.3418)
		(width 0.18288)
		(layer "In2.Cu")
		(net "M_B_CPU0_SA_DQ<17>")
	)
	(segment
		(start 298.716954 -296.3418)
		(end 298.656248 -296.281094)
		(width 0.18288)
		(layer "In2.Cu")
		(net "M_B_CPU0_SA_DQ<17>")
	)
	(segment
		(start 309.503826 -291.034978)
		(end 309.929276 -291.460428)
		(width 0.18288)
		(layer "In2.Cu")
		(net "M_B_CPU0_SA_DQ<17>")
	)
	(segment
		(start 299.464984 -296.186098)
		(end 299.309282 -296.3418)
		(width 0.18288)
		(layer "In2.Cu")
		(net "M_B_CPU0_SA_DQ<17>")
	)
	(segment
		(start 304.590958 -294.60571)
		(end 303.092358 -296.10431)
		(width 0.18288)
		(layer "In2.Cu")
		(net "M_B_CPU0_SA_DQ<17>")
	)
	(segment
		(start 313.826652 -287.801558)
		(end 311.559956 -287.801558)
		(width 0.18288)
		(layer "In2.Cu")
		(net "M_B_CPU0_SA_DQ<17>")
	)
	(segment
		(start 296.82948 -296.562018)
		(end 295.549828 -296.562018)
		(width 0.18288)
		(layer "In2.Cu")
		(net "M_B_CPU0_SA_DQ<17>")
	)
	(segment
		(start 302.162464 -296.323004)
		(end 300.476412 -296.323004)
		(width 0.18288)
		(layer "In2.Cu")
		(net "M_B_CPU0_SA_DQ<17>")
	)
	(segment
		(start 309.929276 -291.86378)
		(end 309.677816 -292.11524)
		(width 0.18288)
		(layer "In2.Cu")
		(net "M_B_CPU0_SA_DQ<17>")
	)
	(segment
		(start 295.549828 -296.562018)
		(end 294.904414 -295.916604)
		(width 0.18288)
		(layer "In2.Cu")
		(net "M_B_CPU0_SA_DQ<17>")
	)
	(segment
		(start 310.485282 -288.876232)
		(end 310.485282 -289.54476)
		(width 0.18288)
		(layer "In2.Cu")
		(net "M_B_CPU0_SA_DQ<17>")
	)
	(segment
		(start 308.659784 -292.11524)
		(end 308.516274 -292.25875)
		(width 0.18288)
		(layer "In2.Cu")
		(net "M_B_CPU0_SA_DQ<17>")
	)
	(arc
		(start 335.068164 -266.617704)
		(mid 334.785462 -266.69348)
		(end 334.50276 -266.617704)
		(width 0.088646)
		(layer "In2.Cu")
		(net "M_B_CPU0_SA_DQ<17>")
	)
	(arc
		(start 334.128364 -266.617704)
		(mid 333.845662 -266.69348)
		(end 333.56296 -266.617704)
		(width 0.088646)
		(layer "In2.Cu")
		(net "M_B_CPU0_SA_DQ<17>")
	)
	(arc
		(start 333.188564 -266.617704)
		(mid 332.905862 -266.69348)
		(end 332.62316 -266.617704)
		(width 0.088646)
		(layer "In2.Cu")
		(net "M_B_CPU0_SA_DQ<17>")
	)
	(arc
		(start 335.44256 -266.617704)
		(mid 335.255362 -266.567527)
		(end 335.068164 -266.617704)
		(width 0.088646)
		(layer "In2.Cu")
		(net "M_B_CPU0_SA_DQ<17>")
	)
	(arc
		(start 336.007964 -266.617704)
		(mid 335.725262 -266.69348)
		(end 335.44256 -266.617704)
		(width 0.088646)
		(layer "In2.Cu")
		(net "M_B_CPU0_SA_DQ<17>")
	)
	(arc
		(start 334.50276 -266.617704)
		(mid 334.315562 -266.567527)
		(end 334.128364 -266.617704)
		(width 0.088646)
		(layer "In2.Cu")
		(net "M_B_CPU0_SA_DQ<17>")
	)
	(arc
		(start 333.56296 -266.617704)
		(mid 333.375762 -266.567527)
		(end 333.188564 -266.617704)
		(width 0.088646)
		(layer "In2.Cu")
		(net "M_B_CPU0_SA_DQ<17>")
	)
	(arc
		(start 332.62316 -266.617704)
		(mid 332.532794 -266.579862)
		(end 332.435708 -266.56665)
		(width 0.088646)
		(layer "In2.Cu")
		(net "M_B_CPU0_SA_DQ<17>")
	)
	(arc
		(start 336.169762 -266.477242)
		(mid 336.095591 -266.555226)
		(end 336.007964 -266.617704)
		(width 0.088646)
		(layer "In2.Cu")
		(net "M_B_CPU0_SA_DQ<17>")
	)
	(segment
		(start 289.48761 -297.191684)
		(end 289.239706 -297.191684)
		(width 0.101854)
		(layer "F.Cu")
		(net "M_B_CPU0_SA_DQ<16>")
	)
	(segment
		(start 288.46018 -297.393106)
		(end 288.46018 -297.682666)
		(width 0.20066)
		(layer "F.Cu")
		(net "M_B_CPU0_SA_DQ<16>")
	)
	(segment
		(start 288.66973 -297.183556)
		(end 288.46018 -297.393106)
		(width 0.20066)
		(layer "F.Cu")
		(net "M_B_CPU0_SA_DQ<16>")
	)
	(segment
		(start 287.589976 -297.616626)
		(end 286.255714 -297.616626)
		(width 0.20066)
		(layer "F.Cu")
		(net "M_B_CPU0_SA_DQ<16>")
	)
	(segment
		(start 287.828736 -297.855386)
		(end 287.589976 -297.616626)
		(width 0.20066)
		(layer "F.Cu")
		(net "M_B_CPU0_SA_DQ<16>")
	)
	(segment
		(start 292.430454 -297.616626)
		(end 292.005512 -297.191684)
		(width 0.20066)
		(layer "F.Cu")
		(net "M_B_CPU0_SA_DQ<16>")
	)
	(segment
		(start 288.28746 -297.855386)
		(end 287.828736 -297.855386)
		(width 0.20066)
		(layer "F.Cu")
		(net "M_B_CPU0_SA_DQ<16>")
	)
	(segment
		(start 291.556694 -297.191684)
		(end 289.48761 -297.191684)
		(width 0.1016)
		(layer "F.Cu")
		(net "M_B_CPU0_SA_DQ<16>")
	)
	(segment
		(start 289.239706 -297.191684)
		(end 289.231578 -297.183556)
		(width 0.101854)
		(layer "F.Cu")
		(net "M_B_CPU0_SA_DQ<16>")
	)
	(segment
		(start 289.231578 -297.183556)
		(end 288.66973 -297.183556)
		(width 0.20066)
		(layer "F.Cu")
		(net "M_B_CPU0_SA_DQ<16>")
	)
	(segment
		(start 288.46018 -297.682666)
		(end 288.28746 -297.855386)
		(width 0.20066)
		(layer "F.Cu")
		(net "M_B_CPU0_SA_DQ<16>")
	)
	(segment
		(start 294.904414 -297.616626)
		(end 293.799514 -297.616626)
		(width 0.20066)
		(layer "F.Cu")
		(net "M_B_CPU0_SA_DQ<16>")
	)
	(segment
		(start 292.005512 -297.191684)
		(end 291.556694 -297.191684)
		(width 0.20066)
		(layer "F.Cu")
		(net "M_B_CPU0_SA_DQ<16>")
	)
	(segment
		(start 337.134962 -266.405868)
		(end 337.134962 -266.941808)
		(width 0.20066)
		(layer "F.Cu")
		(net "M_B_CPU0_SA_DQ<16>")
	)
	(segment
		(start 293.799514 -297.616626)
		(end 292.430454 -297.616626)
		(width 0.20066)
		(layer "F.Cu")
		(net "M_B_CPU0_SA_DQ<16>")
	)
	(segment
		(start 296.891964 -298.195746)
		(end 296.302684 -298.195746)
		(width 0.18288)
		(layer "In2.Cu")
		(net "M_B_CPU0_SA_DQ<16>")
	)
	(segment
		(start 320.714878 -279.810464)
		(end 320.714878 -281.247596)
		(width 0.18288)
		(layer "In2.Cu")
		(net "M_B_CPU0_SA_DQ<16>")
	)
	(segment
		(start 308.736746 -295.021762)
		(end 308.024276 -295.497758)
		(width 0.18288)
		(layer "In2.Cu")
		(net "M_B_CPU0_SA_DQ<16>")
	)
	(segment
		(start 311.843674 -290.642802)
		(end 310.85028 -293.040562)
		(width 0.18288)
		(layer "In2.Cu")
		(net "M_B_CPU0_SA_DQ<16>")
	)
	(segment
		(start 337.134962 -266.941808)
		(end 337.44789 -266.941808)
		(width 0.088646)
		(layer "In2.Cu")
		(net "M_B_CPU0_SA_DQ<16>")
	)
	(segment
		(start 306.173378 -297.180762)
		(end 304.137568 -297.180762)
		(width 0.18288)
		(layer "In2.Cu")
		(net "M_B_CPU0_SA_DQ<16>")
	)
	(segment
		(start 302.180498 -297.99153)
		(end 299.673518 -297.99153)
		(width 0.18288)
		(layer "In2.Cu")
		(net "M_B_CPU0_SA_DQ<16>")
	)
	(segment
		(start 299.623226 -298.041822)
		(end 297.045888 -298.041822)
		(width 0.18288)
		(layer "In2.Cu")
		(net "M_B_CPU0_SA_DQ<16>")
	)
	(segment
		(start 326.942704 -272.77441)
		(end 326.942704 -273.582638)
		(width 0.18288)
		(layer "In2.Cu")
		(net "M_B_CPU0_SA_DQ<16>")
	)
	(segment
		(start 331.646276 -268.070838)
		(end 326.942704 -272.77441)
		(width 0.18288)
		(layer "In2.Cu")
		(net "M_B_CPU0_SA_DQ<16>")
	)
	(segment
		(start 320.714878 -281.247596)
		(end 316.25032 -285.712154)
		(width 0.18288)
		(layer "In2.Cu")
		(net "M_B_CPU0_SA_DQ<16>")
	)
	(segment
		(start 313.973718 -289.511486)
		(end 312.26887 -290.217606)
		(width 0.18288)
		(layer "In2.Cu")
		(net "M_B_CPU0_SA_DQ<16>")
	)
	(segment
		(start 332.435962 -267.507212)
		(end 332.209902 -267.507212)
		(width 0.088646)
		(layer "In2.Cu")
		(net "M_B_CPU0_SA_DQ<16>")
	)
	(segment
		(start 336.947764 -266.617704)
		(end 336.93354 -266.625832)
		(width 0.088646)
		(layer "In2.Cu")
		(net "M_B_CPU0_SA_DQ<16>")
	)
	(segment
		(start 336.760312 -266.941808)
		(end 336.760312 -266.96035)
		(width 0.088646)
		(layer "In2.Cu")
		(net "M_B_CPU0_SA_DQ<16>")
	)
	(segment
		(start 308.024276 -295.497758)
		(end 307.155088 -296.366946)
		(width 0.18288)
		(layer "In2.Cu")
		(net "M_B_CPU0_SA_DQ<16>")
	)
	(segment
		(start 316.25032 -285.712154)
		(end 314.945776 -288.862008)
		(width 0.18288)
		(layer "In2.Cu")
		(net "M_B_CPU0_SA_DQ<16>")
	)
	(segment
		(start 326.942704 -273.582638)
		(end 320.714878 -279.810464)
		(width 0.18288)
		(layer "In2.Cu")
		(net "M_B_CPU0_SA_DQ<16>")
	)
	(segment
		(start 297.045888 -298.041822)
		(end 296.891964 -298.195746)
		(width 0.18288)
		(layer "In2.Cu")
		(net "M_B_CPU0_SA_DQ<16>")
	)
	(segment
		(start 310.85028 -293.040562)
		(end 310.009286 -294.299132)
		(width 0.18288)
		(layer "In2.Cu")
		(net "M_B_CPU0_SA_DQ<16>")
	)
	(segment
		(start 296.302684 -298.195746)
		(end 294.904414 -297.616626)
		(width 0.18288)
		(layer "In2.Cu")
		(net "M_B_CPU0_SA_DQ<16>")
	)
	(segment
		(start 304.137568 -297.180762)
		(end 302.180498 -297.99153)
		(width 0.18288)
		(layer "In2.Cu")
		(net "M_B_CPU0_SA_DQ<16>")
	)
	(segment
		(start 307.155088 -296.366946)
		(end 306.173378 -297.180762)
		(width 0.18288)
		(layer "In2.Cu")
		(net "M_B_CPU0_SA_DQ<16>")
	)
	(segment
		(start 314.945776 -288.862008)
		(end 313.973718 -289.511486)
		(width 0.18288)
		(layer "In2.Cu")
		(net "M_B_CPU0_SA_DQ<16>")
	)
	(segment
		(start 309.675276 -294.633142)
		(end 308.736746 -295.021762)
		(width 0.18288)
		(layer "In2.Cu")
		(net "M_B_CPU0_SA_DQ<16>")
	)
	(segment
		(start 332.209902 -267.507212)
		(end 331.646276 -268.070838)
		(width 0.088646)
		(layer "In2.Cu")
		(net "M_B_CPU0_SA_DQ<16>")
	)
	(segment
		(start 337.336384 -266.625832)
		(end 337.32216 -266.617704)
		(width 0.088646)
		(layer "In2.Cu")
		(net "M_B_CPU0_SA_DQ<16>")
	)
	(segment
		(start 337.44789 -266.941808)
		(end 337.50504 -266.884658)
		(width 0.088646)
		(layer "In2.Cu")
		(net "M_B_CPU0_SA_DQ<16>")
	)
	(segment
		(start 310.009286 -294.299132)
		(end 309.675276 -294.633142)
		(width 0.18288)
		(layer "In2.Cu")
		(net "M_B_CPU0_SA_DQ<16>")
	)
	(segment
		(start 299.673518 -297.99153)
		(end 299.623226 -298.041822)
		(width 0.18288)
		(layer "In2.Cu")
		(net "M_B_CPU0_SA_DQ<16>")
	)
	(segment
		(start 312.26887 -290.217606)
		(end 311.843674 -290.642802)
		(width 0.18288)
		(layer "In2.Cu")
		(net "M_B_CPU0_SA_DQ<16>")
	)
	(arc
		(start 336.477864 -267.43152)
		(mid 336.195162 -267.507262)
		(end 335.91246 -267.43152)
		(width 0.088646)
		(layer "In2.Cu")
		(net "M_B_CPU0_SA_DQ<16>")
	)
	(arc
		(start 334.03286 -267.43152)
		(mid 333.845662 -267.381377)
		(end 333.658464 -267.43152)
		(width 0.088646)
		(layer "In2.Cu")
		(net "M_B_CPU0_SA_DQ<16>")
	)
	(arc
		(start 334.97266 -267.43152)
		(mid 334.785462 -267.381377)
		(end 334.598264 -267.43152)
		(width 0.088646)
		(layer "In2.Cu")
		(net "M_B_CPU0_SA_DQ<16>")
	)
	(arc
		(start 337.50504 -266.884658)
		(mid 337.448645 -266.737038)
		(end 337.336384 -266.625832)
		(width 0.088646)
		(layer "In2.Cu")
		(net "M_B_CPU0_SA_DQ<16>")
	)
	(arc
		(start 336.93354 -266.625832)
		(mid 336.806497 -266.761648)
		(end 336.760312 -266.941808)
		(width 0.088646)
		(layer "In2.Cu")
		(net "M_B_CPU0_SA_DQ<16>")
	)
	(arc
		(start 335.538064 -267.43152)
		(mid 335.255362 -267.507262)
		(end 334.97266 -267.43152)
		(width 0.088646)
		(layer "In2.Cu")
		(net "M_B_CPU0_SA_DQ<16>")
	)
	(arc
		(start 336.760312 -266.96035)
		(mid 336.68015 -267.232539)
		(end 336.477864 -267.43152)
		(width 0.088646)
		(layer "In2.Cu")
		(net "M_B_CPU0_SA_DQ<16>")
	)
	(arc
		(start 333.658464 -267.43152)
		(mid 333.375762 -267.507262)
		(end 333.09306 -267.43152)
		(width 0.088646)
		(layer "In2.Cu")
		(net "M_B_CPU0_SA_DQ<16>")
	)
	(arc
		(start 333.09306 -267.43152)
		(mid 332.905862 -267.381377)
		(end 332.718664 -267.43152)
		(width 0.088646)
		(layer "In2.Cu")
		(net "M_B_CPU0_SA_DQ<16>")
	)
	(arc
		(start 332.718664 -267.43152)
		(mid 332.582294 -267.487973)
		(end 332.435962 -267.507212)
		(width 0.088646)
		(layer "In2.Cu")
		(net "M_B_CPU0_SA_DQ<16>")
	)
	(arc
		(start 335.91246 -267.43152)
		(mid 335.725262 -267.381377)
		(end 335.538064 -267.43152)
		(width 0.088646)
		(layer "In2.Cu")
		(net "M_B_CPU0_SA_DQ<16>")
	)
	(arc
		(start 334.598264 -267.43152)
		(mid 334.315562 -267.507262)
		(end 334.03286 -267.43152)
		(width 0.088646)
		(layer "In2.Cu")
		(net "M_B_CPU0_SA_DQ<16>")
	)
	(arc
		(start 337.32216 -266.617704)
		(mid 337.134962 -266.567527)
		(end 336.947764 -266.617704)
		(width 0.088646)
		(layer "In2.Cu")
		(net "M_B_CPU0_SA_DQ<16>")
	)
	(segment
		(start 292.927532 -298.891706)
		(end 292.689534 -298.891706)
		(width 0.101854)
		(layer "F.Cu")
		(net "M_B_CPU0_SA_DQ<15>")
	)
	(segment
		(start 299.029882 -298.466764)
		(end 297.899582 -298.466764)
		(width 0.20066)
		(layer "F.Cu")
		(net "M_B_CPU0_SA_DQ<15>")
	)
	(segment
		(start 297.899582 -298.466764)
		(end 297.08348 -298.466764)
		(width 0.20066)
		(layer "F.Cu")
		(net "M_B_CPU0_SA_DQ<15>")
	)
	(segment
		(start 296.875962 -298.674282)
		(end 296.42943 -298.674282)
		(width 0.20066)
		(layer "F.Cu")
		(net "M_B_CPU0_SA_DQ<15>")
	)
	(segment
		(start 292.178994 -298.763436)
		(end 292.178994 -298.592748)
		(width 0.20066)
		(layer "F.Cu")
		(net "M_B_CPU0_SA_DQ<15>")
	)
	(segment
		(start 292.67531 -298.90593)
		(end 292.321488 -298.90593)
		(width 0.20066)
		(layer "F.Cu")
		(net "M_B_CPU0_SA_DQ<15>")
	)
	(segment
		(start 341.364316 -271.011142)
		(end 341.364062 -271.011396)
		(width 0.20066)
		(layer "F.Cu")
		(net "M_B_CPU0_SA_DQ<15>")
	)
	(segment
		(start 292.05301 -298.466764)
		(end 290.355782 -298.466764)
		(width 0.20066)
		(layer "F.Cu")
		(net "M_B_CPU0_SA_DQ<15>")
	)
	(segment
		(start 295.544748 -298.891706)
		(end 295.000426 -298.891706)
		(width 0.20066)
		(layer "F.Cu")
		(net "M_B_CPU0_SA_DQ<15>")
	)
	(segment
		(start 292.321488 -298.90593)
		(end 292.178994 -298.763436)
		(width 0.20066)
		(layer "F.Cu")
		(net "M_B_CPU0_SA_DQ<15>")
	)
	(segment
		(start 295.82237 -298.462446)
		(end 295.693846 -298.59097)
		(width 0.20066)
		(layer "F.Cu")
		(net "M_B_CPU0_SA_DQ<15>")
	)
	(segment
		(start 292.689534 -298.891706)
		(end 292.67531 -298.90593)
		(width 0.101854)
		(layer "F.Cu")
		(net "M_B_CPU0_SA_DQ<15>")
	)
	(segment
		(start 295.693846 -298.59097)
		(end 295.693846 -298.742608)
		(width 0.20066)
		(layer "F.Cu")
		(net "M_B_CPU0_SA_DQ<15>")
	)
	(segment
		(start 295.693846 -298.742608)
		(end 295.544748 -298.891706)
		(width 0.20066)
		(layer "F.Cu")
		(net "M_B_CPU0_SA_DQ<15>")
	)
	(segment
		(start 296.217594 -298.462446)
		(end 295.82237 -298.462446)
		(width 0.20066)
		(layer "F.Cu")
		(net "M_B_CPU0_SA_DQ<15>")
	)
	(segment
		(start 297.08348 -298.466764)
		(end 296.875962 -298.674282)
		(width 0.20066)
		(layer "F.Cu")
		(net "M_B_CPU0_SA_DQ<15>")
	)
	(segment
		(start 292.178994 -298.592748)
		(end 292.05301 -298.466764)
		(width 0.20066)
		(layer "F.Cu")
		(net "M_B_CPU0_SA_DQ<15>")
	)
	(segment
		(start 341.364316 -270.475456)
		(end 341.364316 -271.011142)
		(width 0.20066)
		(layer "F.Cu")
		(net "M_B_CPU0_SA_DQ<15>")
	)
	(segment
		(start 296.42943 -298.674282)
		(end 296.217594 -298.462446)
		(width 0.20066)
		(layer "F.Cu")
		(net "M_B_CPU0_SA_DQ<15>")
	)
	(segment
		(start 295.000426 -298.891706)
		(end 292.927532 -298.891706)
		(width 0.1016)
		(layer "F.Cu")
		(net "M_B_CPU0_SA_DQ<15>")
	)
	(segment
		(start 338.833206 -270.52524)
		(end 338.821522 -270.518636)
		(width 0.088646)
		(layer "In4.Cu")
		(net "M_B_CPU0_SA_DQ<15>")
	)
	(segment
		(start 303.343056 -298.774358)
		(end 302.990758 -299.126656)
		(width 0.18288)
		(layer "In4.Cu")
		(net "M_B_CPU0_SA_DQ<15>")
	)
	(segment
		(start 304.42662 -298.059348)
		(end 303.86401 -298.059348)
		(width 0.18288)
		(layer "In4.Cu")
		(net "M_B_CPU0_SA_DQ<15>")
	)
	(segment
		(start 309.752746 -294.709342)
		(end 308.731412 -295.730676)
		(width 0.18288)
		(layer "In4.Cu")
		(net "M_B_CPU0_SA_DQ<15>")
	)
	(segment
		(start 316.33287 -291.579046)
		(end 316.102746 -291.80917)
		(width 0.18288)
		(layer "In4.Cu")
		(net "M_B_CPU0_SA_DQ<15>")
	)
	(segment
		(start 333.351886 -270.68399)
		(end 333.220314 -270.815816)
		(width 0.088646)
		(layer "In4.Cu")
		(net "M_B_CPU0_SA_DQ<15>")
	)
	(segment
		(start 318.613282 -289.691318)
		(end 318.546226 -289.624262)
		(width 0.18288)
		(layer "In4.Cu")
		(net "M_B_CPU0_SA_DQ<15>")
	)
	(segment
		(start 316.102746 -291.80917)
		(end 316.102746 -292.067742)
		(width 0.18288)
		(layer "In4.Cu")
		(net "M_B_CPU0_SA_DQ<15>")
	)
	(segment
		(start 313.447938 -294.152066)
		(end 312.761884 -294.152066)
		(width 0.18288)
		(layer "In4.Cu")
		(net "M_B_CPU0_SA_DQ<15>")
	)
	(segment
		(start 318.05753 -289.854386)
		(end 318.05753 -290.112958)
		(width 0.18288)
		(layer "In4.Cu")
		(net "M_B_CPU0_SA_DQ<15>")
	)
	(segment
		(start 318.05753 -290.112958)
		(end 318.124586 -290.180014)
		(width 0.18288)
		(layer "In4.Cu")
		(net "M_B_CPU0_SA_DQ<15>")
	)
	(segment
		(start 317.568834 -290.601654)
		(end 317.310262 -290.601654)
		(width 0.18288)
		(layer "In4.Cu")
		(net "M_B_CPU0_SA_DQ<15>")
	)
	(segment
		(start 341.051388 -271.011396)
		(end 340.985856 -270.945864)
		(width 0.088646)
		(layer "In4.Cu")
		(net "M_B_CPU0_SA_DQ<15>")
	)
	(segment
		(start 299.689774 -299.126656)
		(end 299.029882 -298.466764)
		(width 0.18288)
		(layer "In4.Cu")
		(net "M_B_CPU0_SA_DQ<15>")
	)
	(segment
		(start 333.22133 -271.302226)
		(end 333.02321 -271.500346)
		(width 0.088646)
		(layer "In4.Cu")
		(net "M_B_CPU0_SA_DQ<15>")
	)
	(segment
		(start 316.169802 -292.134798)
		(end 316.169802 -292.393116)
		(width 0.18288)
		(layer "In4.Cu")
		(net "M_B_CPU0_SA_DQ<15>")
	)
	(segment
		(start 318.124586 -290.438332)
		(end 317.894462 -290.668456)
		(width 0.18288)
		(layer "In4.Cu")
		(net "M_B_CPU0_SA_DQ<15>")
	)
	(segment
		(start 339.773006 -270.52524)
		(end 339.761322 -270.518636)
		(width 0.088646)
		(layer "In4.Cu")
		(net "M_B_CPU0_SA_DQ<15>")
	)
	(segment
		(start 316.102746 -292.067742)
		(end 316.169802 -292.134798)
		(width 0.18288)
		(layer "In4.Cu")
		(net "M_B_CPU0_SA_DQ<15>")
	)
	(segment
		(start 318.546226 -289.624262)
		(end 318.287654 -289.624262)
		(width 0.18288)
		(layer "In4.Cu")
		(net "M_B_CPU0_SA_DQ<15>")
	)
	(segment
		(start 322.23075 -282.078176)
		(end 319.223136 -289.339782)
		(width 0.18288)
		(layer "In4.Cu")
		(net "M_B_CPU0_SA_DQ<15>")
	)
	(segment
		(start 331.267308 -273.040094)
		(end 322.23075 -282.078176)
		(width 0.18288)
		(layer "In4.Cu")
		(net "M_B_CPU0_SA_DQ<15>")
	)
	(segment
		(start 333.220314 -270.815816)
		(end 333.22133 -271.302226)
		(width 0.088646)
		(layer "In4.Cu")
		(net "M_B_CPU0_SA_DQ<15>")
	)
	(segment
		(start 315.19241 -293.11219)
		(end 315.19241 -293.370508)
		(width 0.18288)
		(layer "In4.Cu")
		(net "M_B_CPU0_SA_DQ<15>")
	)
	(segment
		(start 315.19241 -293.370508)
		(end 314.831984 -293.730934)
		(width 0.18288)
		(layer "In4.Cu")
		(net "M_B_CPU0_SA_DQ<15>")
	)
	(segment
		(start 301.40529 -298.375324)
		(end 301.156116 -298.624498)
		(width 0.18288)
		(layer "In4.Cu")
		(net "M_B_CPU0_SA_DQ<15>")
	)
	(segment
		(start 308.731412 -295.730676)
		(end 307.848 -295.730676)
		(width 0.18288)
		(layer "In4.Cu")
		(net "M_B_CPU0_SA_DQ<15>")
	)
	(segment
		(start 337.891882 -270.524478)
		(end 337.887564 -270.521938)
		(width 0.088646)
		(layer "In4.Cu")
		(net "M_B_CPU0_SA_DQ<15>")
	)
	(segment
		(start 306.095654 -296.616374)
		(end 304.652934 -298.059094)
		(width 0.18288)
		(layer "In4.Cu")
		(net "M_B_CPU0_SA_DQ<15>")
	)
	(segment
		(start 311.935622 -294.978328)
		(end 311.606946 -294.978328)
		(width 0.18288)
		(layer "In4.Cu")
		(net "M_B_CPU0_SA_DQ<15>")
	)
	(segment
		(start 316.169802 -292.393116)
		(end 315.939678 -292.62324)
		(width 0.18288)
		(layer "In4.Cu")
		(net "M_B_CPU0_SA_DQ<15>")
	)
	(segment
		(start 340.706964 -270.521938)
		(end 340.701122 -270.518636)
		(width 0.088646)
		(layer "In4.Cu")
		(net "M_B_CPU0_SA_DQ<15>")
	)
	(segment
		(start 315.939678 -292.62324)
		(end 315.681106 -292.623494)
		(width 0.18288)
		(layer "In4.Cu")
		(net "M_B_CPU0_SA_DQ<15>")
	)
	(segment
		(start 301.156116 -298.943776)
		(end 300.973236 -299.126656)
		(width 0.18288)
		(layer "In4.Cu")
		(net "M_B_CPU0_SA_DQ<15>")
	)
	(segment
		(start 317.147194 -291.157406)
		(end 317.147194 -291.415724)
		(width 0.18288)
		(layer "In4.Cu")
		(net "M_B_CPU0_SA_DQ<15>")
	)
	(segment
		(start 303.86401 -298.059348)
		(end 303.093374 -297.288712)
		(width 0.18288)
		(layer "In4.Cu")
		(net "M_B_CPU0_SA_DQ<15>")
	)
	(segment
		(start 315.681106 -292.623494)
		(end 315.61405 -292.556438)
		(width 0.18288)
		(layer "In4.Cu")
		(net "M_B_CPU0_SA_DQ<15>")
	)
	(segment
		(start 301.156116 -298.624498)
		(end 301.156116 -298.943776)
		(width 0.18288)
		(layer "In4.Cu")
		(net "M_B_CPU0_SA_DQ<15>")
	)
	(segment
		(start 318.287654 -289.624262)
		(end 318.05753 -289.854386)
		(width 0.18288)
		(layer "In4.Cu")
		(net "M_B_CPU0_SA_DQ<15>")
	)
	(segment
		(start 311.606946 -294.978328)
		(end 310.958738 -294.33012)
		(width 0.18288)
		(layer "In4.Cu")
		(net "M_B_CPU0_SA_DQ<15>")
	)
	(segment
		(start 306.57165 -296.616374)
		(end 306.095654 -296.616374)
		(width 0.18288)
		(layer "In4.Cu")
		(net "M_B_CPU0_SA_DQ<15>")
	)
	(segment
		(start 304.652934 -298.059094)
		(end 304.42662 -298.059348)
		(width 0.18288)
		(layer "In4.Cu")
		(net "M_B_CPU0_SA_DQ<15>")
	)
	(segment
		(start 302.591724 -297.505628)
		(end 302.591724 -297.7642)
		(width 0.18288)
		(layer "In4.Cu")
		(net "M_B_CPU0_SA_DQ<15>")
	)
	(segment
		(start 318.124586 -290.180014)
		(end 318.124586 -290.438332)
		(width 0.18288)
		(layer "In4.Cu")
		(net "M_B_CPU0_SA_DQ<15>")
	)
	(segment
		(start 302.990758 -299.126656)
		(end 302.029876 -299.126656)
		(width 0.18288)
		(layer "In4.Cu")
		(net "M_B_CPU0_SA_DQ<15>")
	)
	(segment
		(start 300.973236 -299.126656)
		(end 299.689774 -299.126656)
		(width 0.18288)
		(layer "In4.Cu")
		(net "M_B_CPU0_SA_DQ<15>")
	)
	(segment
		(start 307.848 -295.730676)
		(end 307.180996 -296.007028)
		(width 0.18288)
		(layer "In4.Cu")
		(net "M_B_CPU0_SA_DQ<15>")
	)
	(segment
		(start 319.223136 -289.339782)
		(end 318.871854 -289.691064)
		(width 0.18288)
		(layer "In4.Cu")
		(net "M_B_CPU0_SA_DQ<15>")
	)
	(segment
		(start 302.029876 -299.126656)
		(end 301.846996 -298.943776)
		(width 0.18288)
		(layer "In4.Cu")
		(net "M_B_CPU0_SA_DQ<15>")
	)
	(segment
		(start 316.591442 -291.579046)
		(end 316.33287 -291.579046)
		(width 0.18288)
		(layer "In4.Cu")
		(net "M_B_CPU0_SA_DQ<15>")
	)
	(segment
		(start 340.708996 -270.523208)
		(end 340.706964 -270.521938)
		(width 0.088646)
		(layer "In4.Cu")
		(net "M_B_CPU0_SA_DQ<15>")
	)
	(segment
		(start 317.147194 -291.415724)
		(end 316.91707 -291.645848)
		(width 0.18288)
		(layer "In4.Cu")
		(net "M_B_CPU0_SA_DQ<15>")
	)
	(segment
		(start 318.871854 -289.691064)
		(end 318.613282 -289.691318)
		(width 0.18288)
		(layer "In4.Cu")
		(net "M_B_CPU0_SA_DQ<15>")
	)
	(segment
		(start 307.180996 -296.007028)
		(end 306.57165 -296.616374)
		(width 0.18288)
		(layer "In4.Cu")
		(net "M_B_CPU0_SA_DQ<15>")
	)
	(segment
		(start 317.310262 -290.601654)
		(end 317.080138 -290.831778)
		(width 0.18288)
		(layer "In4.Cu")
		(net "M_B_CPU0_SA_DQ<15>")
	)
	(segment
		(start 313.86907 -293.730934)
		(end 313.447938 -294.152066)
		(width 0.18288)
		(layer "In4.Cu")
		(net "M_B_CPU0_SA_DQ<15>")
	)
	(segment
		(start 341.364062 -271.011396)
		(end 341.051388 -271.011396)
		(width 0.088646)
		(layer "In4.Cu")
		(net "M_B_CPU0_SA_DQ<15>")
	)
	(segment
		(start 316.658498 -291.646102)
		(end 316.591442 -291.579046)
		(width 0.18288)
		(layer "In4.Cu")
		(net "M_B_CPU0_SA_DQ<15>")
	)
	(segment
		(start 301.846996 -298.943776)
		(end 301.846996 -298.558204)
		(width 0.18288)
		(layer "In4.Cu")
		(net "M_B_CPU0_SA_DQ<15>")
	)
	(segment
		(start 316.91707 -291.645848)
		(end 316.658498 -291.646102)
		(width 0.18288)
		(layer "In4.Cu")
		(net "M_B_CPU0_SA_DQ<15>")
	)
	(segment
		(start 301.664116 -298.375324)
		(end 301.40529 -298.375324)
		(width 0.18288)
		(layer "In4.Cu")
		(net "M_B_CPU0_SA_DQ<15>")
	)
	(segment
		(start 317.080138 -291.09035)
		(end 317.147194 -291.157406)
		(width 0.18288)
		(layer "In4.Cu")
		(net "M_B_CPU0_SA_DQ<15>")
	)
	(segment
		(start 333.02321 -271.500346)
		(end 331.483462 -273.040094)
		(width 0.18288)
		(layer "In4.Cu")
		(net "M_B_CPU0_SA_DQ<15>")
	)
	(segment
		(start 315.355478 -292.556438)
		(end 315.125354 -292.786562)
		(width 0.18288)
		(layer "In4.Cu")
		(net "M_B_CPU0_SA_DQ<15>")
	)
	(segment
		(start 314.831984 -293.730934)
		(end 313.86907 -293.730934)
		(width 0.18288)
		(layer "In4.Cu")
		(net "M_B_CPU0_SA_DQ<15>")
	)
	(segment
		(start 315.125354 -293.045134)
		(end 315.19241 -293.11219)
		(width 0.18288)
		(layer "In4.Cu")
		(net "M_B_CPU0_SA_DQ<15>")
	)
	(segment
		(start 310.958738 -294.33012)
		(end 310.667654 -294.33012)
		(width 0.18288)
		(layer "In4.Cu")
		(net "M_B_CPU0_SA_DQ<15>")
	)
	(segment
		(start 315.61405 -292.556438)
		(end 315.355478 -292.556438)
		(width 0.18288)
		(layer "In4.Cu")
		(net "M_B_CPU0_SA_DQ<15>")
	)
	(segment
		(start 336.951574 -270.524224)
		(end 336.947764 -270.521938)
		(width 0.088646)
		(layer "In4.Cu")
		(net "M_B_CPU0_SA_DQ<15>")
	)
	(segment
		(start 331.483462 -273.040094)
		(end 331.267308 -273.040094)
		(width 0.18288)
		(layer "In4.Cu")
		(net "M_B_CPU0_SA_DQ<15>")
	)
	(segment
		(start 302.80864 -297.288712)
		(end 302.591724 -297.505628)
		(width 0.18288)
		(layer "In4.Cu")
		(net "M_B_CPU0_SA_DQ<15>")
	)
	(segment
		(start 301.846996 -298.558204)
		(end 301.664116 -298.375324)
		(width 0.18288)
		(layer "In4.Cu")
		(net "M_B_CPU0_SA_DQ<15>")
	)
	(segment
		(start 310.667654 -294.33012)
		(end 309.752746 -294.709342)
		(width 0.18288)
		(layer "In4.Cu")
		(net "M_B_CPU0_SA_DQ<15>")
	)
	(segment
		(start 303.093374 -297.288712)
		(end 302.80864 -297.288712)
		(width 0.18288)
		(layer "In4.Cu")
		(net "M_B_CPU0_SA_DQ<15>")
	)
	(segment
		(start 315.125354 -292.786562)
		(end 315.125354 -293.045134)
		(width 0.18288)
		(layer "In4.Cu")
		(net "M_B_CPU0_SA_DQ<15>")
	)
	(segment
		(start 336.947764 -270.521938)
		(end 336.941922 -270.518636)
		(width 0.088646)
		(layer "In4.Cu")
		(net "M_B_CPU0_SA_DQ<15>")
	)
	(segment
		(start 336.012282 -270.524478)
		(end 336.007964 -270.521938)
		(width 0.088646)
		(layer "In4.Cu")
		(net "M_B_CPU0_SA_DQ<15>")
	)
	(segment
		(start 302.591724 -297.7642)
		(end 303.343056 -298.515532)
		(width 0.18288)
		(layer "In4.Cu")
		(net "M_B_CPU0_SA_DQ<15>")
	)
	(segment
		(start 312.761884 -294.152066)
		(end 311.935622 -294.978328)
		(width 0.18288)
		(layer "In4.Cu")
		(net "M_B_CPU0_SA_DQ<15>")
	)
	(segment
		(start 303.343056 -298.515532)
		(end 303.343056 -298.774358)
		(width 0.18288)
		(layer "In4.Cu")
		(net "M_B_CPU0_SA_DQ<15>")
	)
	(segment
		(start 317.894462 -290.668456)
		(end 317.63589 -290.66871)
		(width 0.18288)
		(layer "In4.Cu")
		(net "M_B_CPU0_SA_DQ<15>")
	)
	(segment
		(start 317.63589 -290.66871)
		(end 317.568834 -290.601654)
		(width 0.18288)
		(layer "In4.Cu")
		(net "M_B_CPU0_SA_DQ<15>")
	)
	(segment
		(start 317.080138 -290.831778)
		(end 317.080138 -291.09035)
		(width 0.18288)
		(layer "In4.Cu")
		(net "M_B_CPU0_SA_DQ<15>")
	)
	(arc
		(start 336.007964 -270.521938)
		(mid 335.725262 -270.446162)
		(end 335.44256 -270.521938)
		(width 0.088646)
		(layer "In4.Cu")
		(net "M_B_CPU0_SA_DQ<15>")
	)
	(arc
		(start 337.322414 -270.521938)
		(mid 337.137293 -270.572201)
		(end 336.951574 -270.524224)
		(width 0.088646)
		(layer "In4.Cu")
		(net "M_B_CPU0_SA_DQ<15>")
	)
	(arc
		(start 334.128364 -270.521938)
		(mid 333.845662 -270.446162)
		(end 333.56296 -270.521938)
		(width 0.088646)
		(layer "In4.Cu")
		(net "M_B_CPU0_SA_DQ<15>")
	)
	(arc
		(start 340.701122 -270.518636)
		(mid 340.421017 -270.446194)
		(end 340.141814 -270.521938)
		(width 0.088646)
		(layer "In4.Cu")
		(net "M_B_CPU0_SA_DQ<15>")
	)
	(arc
		(start 336.382614 -270.521938)
		(mid 336.197777 -270.572199)
		(end 336.012282 -270.524478)
		(width 0.088646)
		(layer "In4.Cu")
		(net "M_B_CPU0_SA_DQ<15>")
	)
	(arc
		(start 338.262214 -270.521938)
		(mid 338.077377 -270.572199)
		(end 337.891882 -270.524478)
		(width 0.088646)
		(layer "In4.Cu")
		(net "M_B_CPU0_SA_DQ<15>")
	)
	(arc
		(start 334.50276 -270.521938)
		(mid 334.315562 -270.572081)
		(end 334.128364 -270.521938)
		(width 0.088646)
		(layer "In4.Cu")
		(net "M_B_CPU0_SA_DQ<15>")
	)
	(arc
		(start 333.56296 -270.521938)
		(mid 333.452065 -270.595985)
		(end 333.351886 -270.68399)
		(width 0.088646)
		(layer "In4.Cu")
		(net "M_B_CPU0_SA_DQ<15>")
	)
	(arc
		(start 337.887564 -270.521938)
		(mid 337.605006 -270.446289)
		(end 337.322414 -270.521938)
		(width 0.088646)
		(layer "In4.Cu")
		(net "M_B_CPU0_SA_DQ<15>")
	)
	(arc
		(start 339.202014 -270.521938)
		(mid 339.01806 -270.572067)
		(end 338.833206 -270.52524)
		(width 0.088646)
		(layer "In4.Cu")
		(net "M_B_CPU0_SA_DQ<15>")
	)
	(arc
		(start 340.141814 -270.521938)
		(mid 339.95786 -270.572067)
		(end 339.773006 -270.52524)
		(width 0.088646)
		(layer "In4.Cu")
		(net "M_B_CPU0_SA_DQ<15>")
	)
	(arc
		(start 338.821522 -270.518636)
		(mid 338.541417 -270.446194)
		(end 338.262214 -270.521938)
		(width 0.088646)
		(layer "In4.Cu")
		(net "M_B_CPU0_SA_DQ<15>")
	)
	(arc
		(start 336.941922 -270.518636)
		(mid 336.661817 -270.446194)
		(end 336.382614 -270.521938)
		(width 0.088646)
		(layer "In4.Cu")
		(net "M_B_CPU0_SA_DQ<15>")
	)
	(arc
		(start 335.068164 -270.521938)
		(mid 334.785462 -270.446162)
		(end 334.50276 -270.521938)
		(width 0.088646)
		(layer "In4.Cu")
		(net "M_B_CPU0_SA_DQ<15>")
	)
	(arc
		(start 339.761322 -270.518636)
		(mid 339.481217 -270.446194)
		(end 339.202014 -270.521938)
		(width 0.088646)
		(layer "In4.Cu")
		(net "M_B_CPU0_SA_DQ<15>")
	)
	(arc
		(start 335.44256 -270.521938)
		(mid 335.255362 -270.572081)
		(end 335.068164 -270.521938)
		(width 0.088646)
		(layer "In4.Cu")
		(net "M_B_CPU0_SA_DQ<15>")
	)
	(arc
		(start 340.985856 -270.945864)
		(mid 340.89726 -270.701902)
		(end 340.708996 -270.523208)
		(width 0.088646)
		(layer "In4.Cu")
		(net "M_B_CPU0_SA_DQ<15>")
	)
	(segment
		(start 292.67531 -299.731684)
		(end 291.937948 -299.731684)
		(width 0.20066)
		(layer "F.Cu")
		(net "M_B_CPU0_SA_DQ<14>")
	)
	(segment
		(start 295.777158 -299.885608)
		(end 295.633394 -299.741844)
		(width 0.20066)
		(layer "F.Cu")
		(net "M_B_CPU0_SA_DQ<14>")
	)
	(segment
		(start 341.833962 -271.289272)
		(end 341.834216 -271.289526)
		(width 0.20066)
		(layer "F.Cu")
		(net "M_B_CPU0_SA_DQ<14>")
	)
	(segment
		(start 299.029882 -300.166786)
		(end 297.899582 -300.166786)
		(width 0.20066)
		(layer "F.Cu")
		(net "M_B_CPU0_SA_DQ<14>")
	)
	(segment
		(start 292.68547 -299.741844)
		(end 292.67531 -299.731684)
		(width 0.101854)
		(layer "F.Cu")
		(net "M_B_CPU0_SA_DQ<14>")
	)
	(segment
		(start 291.937948 -299.731684)
		(end 291.502846 -300.166786)
		(width 0.20066)
		(layer "F.Cu")
		(net "M_B_CPU0_SA_DQ<14>")
	)
	(segment
		(start 295.944544 -300.378622)
		(end 295.777158 -300.211236)
		(width 0.20066)
		(layer "F.Cu")
		(net "M_B_CPU0_SA_DQ<14>")
	)
	(segment
		(start 295.633394 -299.741844)
		(end 295.000426 -299.741844)
		(width 0.20066)
		(layer "F.Cu")
		(net "M_B_CPU0_SA_DQ<14>")
	)
	(segment
		(start 297.899582 -300.166786)
		(end 296.584878 -300.166786)
		(width 0.20066)
		(layer "F.Cu")
		(net "M_B_CPU0_SA_DQ<14>")
	)
	(segment
		(start 296.584878 -300.166786)
		(end 296.373042 -300.378622)
		(width 0.20066)
		(layer "F.Cu")
		(net "M_B_CPU0_SA_DQ<14>")
	)
	(segment
		(start 296.373042 -300.378622)
		(end 295.944544 -300.378622)
		(width 0.20066)
		(layer "F.Cu")
		(net "M_B_CPU0_SA_DQ<14>")
	)
	(segment
		(start 341.834216 -271.289526)
		(end 341.834216 -271.825212)
		(width 0.20066)
		(layer "F.Cu")
		(net "M_B_CPU0_SA_DQ<14>")
	)
	(segment
		(start 295.777158 -300.211236)
		(end 295.777158 -299.885608)
		(width 0.20066)
		(layer "F.Cu")
		(net "M_B_CPU0_SA_DQ<14>")
	)
	(segment
		(start 291.502846 -300.166786)
		(end 290.355782 -300.166786)
		(width 0.20066)
		(layer "F.Cu")
		(net "M_B_CPU0_SA_DQ<14>")
	)
	(segment
		(start 295.000426 -299.741844)
		(end 292.940486 -299.741844)
		(width 0.1016)
		(layer "F.Cu")
		(net "M_B_CPU0_SA_DQ<14>")
	)
	(segment
		(start 292.940486 -299.741844)
		(end 292.68547 -299.741844)
		(width 0.101854)
		(layer "F.Cu")
		(net "M_B_CPU0_SA_DQ<14>")
	)
	(segment
		(start 312.711338 -295.685718)
		(end 312.711338 -296.055796)
		(width 0.18288)
		(layer "In4.Cu")
		(net "M_B_CPU0_SA_DQ<14>")
	)
	(segment
		(start 301.356014 -300.269148)
		(end 301.030894 -300.269148)
		(width 0.18288)
		(layer "In4.Cu")
		(net "M_B_CPU0_SA_DQ<14>")
	)
	(segment
		(start 307.485796 -297.311064)
		(end 306.649374 -298.147486)
		(width 0.18288)
		(layer "In4.Cu")
		(net "M_B_CPU0_SA_DQ<14>")
	)
	(segment
		(start 308.160166 -297.311064)
		(end 307.485796 -297.311064)
		(width 0.18288)
		(layer "In4.Cu")
		(net "M_B_CPU0_SA_DQ<14>")
	)
	(segment
		(start 316.901322 -293.198042)
		(end 316.901322 -293.456614)
		(width 0.18288)
		(layer "In4.Cu")
		(net "M_B_CPU0_SA_DQ<14>")
	)
	(segment
		(start 300.848014 -300.452028)
		(end 300.848014 -300.6852)
		(width 0.18288)
		(layer "In4.Cu")
		(net "M_B_CPU0_SA_DQ<14>")
	)
	(segment
		(start 315.92393 -294.175434)
		(end 315.92393 -294.434006)
		(width 0.18288)
		(layer "In4.Cu")
		(net "M_B_CPU0_SA_DQ<14>")
	)
	(segment
		(start 339.671914 -271.335754)
		(end 339.666072 -271.33931)
		(width 0.088646)
		(layer "In4.Cu")
		(net "M_B_CPU0_SA_DQ<14>")
	)
	(segment
		(start 302.92548 -300.86808)
		(end 301.721774 -300.86808)
		(width 0.18288)
		(layer "In4.Cu")
		(net "M_B_CPU0_SA_DQ<14>")
	)
	(segment
		(start 299.731176 -300.86808)
		(end 299.029882 -300.166786)
		(width 0.18288)
		(layer "In4.Cu")
		(net "M_B_CPU0_SA_DQ<14>")
	)
	(segment
		(start 318.573658 -292.196774)
		(end 318.36741 -291.990526)
		(width 0.18288)
		(layer "In4.Cu")
		(net "M_B_CPU0_SA_DQ<14>")
	)
	(segment
		(start 318.36741 -291.990526)
		(end 318.108838 -291.990526)
		(width 0.18288)
		(layer "In4.Cu")
		(net "M_B_CPU0_SA_DQ<14>")
	)
	(segment
		(start 331.690726 -274.10156)
		(end 323.10578 -282.686506)
		(width 0.18288)
		(layer "In4.Cu")
		(net "M_B_CPU0_SA_DQ<14>")
	)
	(segment
		(start 331.934312 -274.10156)
		(end 331.690726 -274.10156)
		(width 0.18288)
		(layer "In4.Cu")
		(net "M_B_CPU0_SA_DQ<14>")
	)
	(segment
		(start 317.596266 -293.174166)
		(end 317.390018 -292.967918)
		(width 0.18288)
		(layer "In4.Cu")
		(net "M_B_CPU0_SA_DQ<14>")
	)
	(segment
		(start 310.767476 -296.535094)
		(end 310.45531 -296.535094)
		(width 0.18288)
		(layer "In4.Cu")
		(net "M_B_CPU0_SA_DQ<14>")
	)
	(segment
		(start 301.538894 -300.6852)
		(end 301.538894 -300.452028)
		(width 0.18288)
		(layer "In4.Cu")
		(net "M_B_CPU0_SA_DQ<14>")
	)
	(segment
		(start 311.133236 -296.169334)
		(end 310.767476 -296.535094)
		(width 0.18288)
		(layer "In4.Cu")
		(net "M_B_CPU0_SA_DQ<14>")
	)
	(segment
		(start 333.093314 -272.96364)
		(end 333.072232 -272.96364)
		(width 0.088646)
		(layer "In4.Cu")
		(net "M_B_CPU0_SA_DQ<14>")
	)
	(segment
		(start 336.857086 -271.333214)
		(end 336.852514 -271.335754)
		(width 0.088646)
		(layer "In4.Cu")
		(net "M_B_CPU0_SA_DQ<14>")
	)
	(segment
		(start 310.160416 -296.2402)
		(end 309.724806 -296.2402)
		(width 0.18288)
		(layer "In4.Cu")
		(net "M_B_CPU0_SA_DQ<14>")
	)
	(segment
		(start 316.130178 -294.898826)
		(end 315.659262 -295.369742)
		(width 0.18288)
		(layer "In4.Cu")
		(net "M_B_CPU0_SA_DQ<14>")
	)
	(segment
		(start 339.677756 -271.332452)
		(end 339.671914 -271.335754)
		(width 0.088646)
		(layer "In4.Cu")
		(net "M_B_CPU0_SA_DQ<14>")
	)
	(segment
		(start 340.617556 -271.332452)
		(end 340.611714 -271.335754)
		(width 0.088646)
		(layer "In4.Cu")
		(net "M_B_CPU0_SA_DQ<14>")
	)
	(segment
		(start 301.030894 -300.269148)
		(end 300.848014 -300.452028)
		(width 0.18288)
		(layer "In4.Cu")
		(net "M_B_CPU0_SA_DQ<14>")
	)
	(segment
		(start 306.649374 -298.147486)
		(end 306.23637 -298.147486)
		(width 0.18288)
		(layer "In4.Cu")
		(net "M_B_CPU0_SA_DQ<14>")
	)
	(segment
		(start 306.23637 -298.147486)
		(end 304.38344 -300.000416)
		(width 0.18288)
		(layer "In4.Cu")
		(net "M_B_CPU0_SA_DQ<14>")
	)
	(segment
		(start 318.83223 -292.196774)
		(end 318.573658 -292.196774)
		(width 0.18288)
		(layer "In4.Cu")
		(net "M_B_CPU0_SA_DQ<14>")
	)
	(segment
		(start 316.618874 -294.151558)
		(end 316.412626 -293.94531)
		(width 0.18288)
		(layer "In4.Cu")
		(net "M_B_CPU0_SA_DQ<14>")
	)
	(segment
		(start 333.280512 -272.62074)
		(end 333.280512 -272.647918)
		(width 0.088646)
		(layer "In4.Cu")
		(net "M_B_CPU0_SA_DQ<14>")
	)
	(segment
		(start 317.854838 -293.174166)
		(end 317.596266 -293.174166)
		(width 0.18288)
		(layer "In4.Cu")
		(net "M_B_CPU0_SA_DQ<14>")
	)
	(segment
		(start 338.737956 -271.332452)
		(end 338.732114 -271.335754)
		(width 0.088646)
		(layer "In4.Cu")
		(net "M_B_CPU0_SA_DQ<14>")
	)
	(segment
		(start 316.901322 -293.456614)
		(end 317.10757 -293.662862)
		(width 0.18288)
		(layer "In4.Cu")
		(net "M_B_CPU0_SA_DQ<14>")
	)
	(segment
		(start 308.90337 -297.061636)
		(end 308.409594 -297.061636)
		(width 0.18288)
		(layer "In4.Cu")
		(net "M_B_CPU0_SA_DQ<14>")
	)
	(segment
		(start 317.878714 -292.479222)
		(end 318.084962 -292.68547)
		(width 0.18288)
		(layer "In4.Cu")
		(net "M_B_CPU0_SA_DQ<14>")
	)
	(segment
		(start 317.390018 -292.967918)
		(end 317.131446 -292.967918)
		(width 0.18288)
		(layer "In4.Cu")
		(net "M_B_CPU0_SA_DQ<14>")
	)
	(segment
		(start 316.130178 -294.640254)
		(end 316.130178 -294.898826)
		(width 0.18288)
		(layer "In4.Cu")
		(net "M_B_CPU0_SA_DQ<14>")
	)
	(segment
		(start 308.409594 -297.061636)
		(end 308.160166 -297.311064)
		(width 0.18288)
		(layer "In4.Cu")
		(net "M_B_CPU0_SA_DQ<14>")
	)
	(segment
		(start 315.659262 -295.369742)
		(end 313.027314 -295.369742)
		(width 0.18288)
		(layer "In4.Cu")
		(net "M_B_CPU0_SA_DQ<14>")
	)
	(segment
		(start 303.23282 -300.34992)
		(end 303.23282 -300.56074)
		(width 0.18288)
		(layer "In4.Cu")
		(net "M_B_CPU0_SA_DQ<14>")
	)
	(segment
		(start 340.611714 -271.335754)
		(end 340.605872 -271.33931)
		(width 0.088646)
		(layer "In4.Cu")
		(net "M_B_CPU0_SA_DQ<14>")
	)
	(segment
		(start 317.878714 -292.22065)
		(end 317.878714 -292.479222)
		(width 0.18288)
		(layer "In4.Cu")
		(net "M_B_CPU0_SA_DQ<14>")
	)
	(segment
		(start 311.35955 -296.169334)
		(end 311.133236 -296.169334)
		(width 0.18288)
		(layer "In4.Cu")
		(net "M_B_CPU0_SA_DQ<14>")
	)
	(segment
		(start 333.072232 -272.96364)
		(end 332.38821 -273.647662)
		(width 0.088646)
		(layer "In4.Cu")
		(net "M_B_CPU0_SA_DQ<14>")
	)
	(segment
		(start 312.711338 -296.055796)
		(end 312.23204 -296.535094)
		(width 0.18288)
		(layer "In4.Cu")
		(net "M_B_CPU0_SA_DQ<14>")
	)
	(segment
		(start 316.412626 -293.94531)
		(end 316.154054 -293.94531)
		(width 0.18288)
		(layer "In4.Cu")
		(net "M_B_CPU0_SA_DQ<14>")
	)
	(segment
		(start 336.852514 -271.335754)
		(end 336.846672 -271.33931)
		(width 0.088646)
		(layer "In4.Cu")
		(net "M_B_CPU0_SA_DQ<14>")
	)
	(segment
		(start 323.10578 -282.686506)
		(end 319.40246 -291.626544)
		(width 0.18288)
		(layer "In4.Cu")
		(net "M_B_CPU0_SA_DQ<14>")
	)
	(segment
		(start 317.10757 -293.921434)
		(end 316.877446 -294.151558)
		(width 0.18288)
		(layer "In4.Cu")
		(net "M_B_CPU0_SA_DQ<14>")
	)
	(segment
		(start 301.721774 -300.86808)
		(end 301.538894 -300.6852)
		(width 0.18288)
		(layer "In4.Cu")
		(net "M_B_CPU0_SA_DQ<14>")
	)
	(segment
		(start 318.108838 -291.990526)
		(end 317.878714 -292.22065)
		(width 0.18288)
		(layer "In4.Cu")
		(net "M_B_CPU0_SA_DQ<14>")
	)
	(segment
		(start 300.665134 -300.86808)
		(end 299.731176 -300.86808)
		(width 0.18288)
		(layer "In4.Cu")
		(net "M_B_CPU0_SA_DQ<14>")
	)
	(segment
		(start 317.131446 -292.967918)
		(end 316.901322 -293.198042)
		(width 0.18288)
		(layer "In4.Cu")
		(net "M_B_CPU0_SA_DQ<14>")
	)
	(segment
		(start 318.084962 -292.944042)
		(end 317.854838 -293.174166)
		(width 0.18288)
		(layer "In4.Cu")
		(net "M_B_CPU0_SA_DQ<14>")
	)
	(segment
		(start 319.40246 -291.626544)
		(end 318.83223 -292.196774)
		(width 0.18288)
		(layer "In4.Cu")
		(net "M_B_CPU0_SA_DQ<14>")
	)
	(segment
		(start 315.92393 -294.434006)
		(end 316.130178 -294.640254)
		(width 0.18288)
		(layer "In4.Cu")
		(net "M_B_CPU0_SA_DQ<14>")
	)
	(segment
		(start 304.38344 -300.000416)
		(end 303.582324 -300.000416)
		(width 0.18288)
		(layer "In4.Cu")
		(net "M_B_CPU0_SA_DQ<14>")
	)
	(segment
		(start 332.38821 -273.647662)
		(end 331.934312 -274.10156)
		(width 0.18288)
		(layer "In4.Cu")
		(net "M_B_CPU0_SA_DQ<14>")
	)
	(segment
		(start 300.848014 -300.6852)
		(end 300.665134 -300.86808)
		(width 0.18288)
		(layer "In4.Cu")
		(net "M_B_CPU0_SA_DQ<14>")
	)
	(segment
		(start 333.750412 -271.815306)
		(end 333.750412 -271.825212)
		(width 0.088646)
		(layer "In4.Cu")
		(net "M_B_CPU0_SA_DQ<14>")
	)
	(segment
		(start 316.877446 -294.151558)
		(end 316.618874 -294.151558)
		(width 0.18288)
		(layer "In4.Cu")
		(net "M_B_CPU0_SA_DQ<14>")
	)
	(segment
		(start 312.23204 -296.535094)
		(end 311.72531 -296.535094)
		(width 0.18288)
		(layer "In4.Cu")
		(net "M_B_CPU0_SA_DQ<14>")
	)
	(segment
		(start 317.10757 -293.662862)
		(end 317.10757 -293.921434)
		(width 0.18288)
		(layer "In4.Cu")
		(net "M_B_CPU0_SA_DQ<14>")
	)
	(segment
		(start 309.724806 -296.2402)
		(end 308.90337 -297.061636)
		(width 0.18288)
		(layer "In4.Cu")
		(net "M_B_CPU0_SA_DQ<14>")
	)
	(segment
		(start 341.257382 -271.38249)
		(end 341.176864 -271.336008)
		(width 0.088646)
		(layer "In4.Cu")
		(net "M_B_CPU0_SA_DQ<14>")
	)
	(segment
		(start 336.477864 -271.336008)
		(end 336.477864 -271.335754)
		(width 0.088646)
		(layer "In4.Cu")
		(net "M_B_CPU0_SA_DQ<14>")
	)
	(segment
		(start 311.72531 -296.535094)
		(end 311.35955 -296.169334)
		(width 0.18288)
		(layer "In4.Cu")
		(net "M_B_CPU0_SA_DQ<14>")
	)
	(segment
		(start 333.57185 -272.14449)
		(end 333.56296 -272.14957)
		(width 0.088646)
		(layer "In4.Cu")
		(net "M_B_CPU0_SA_DQ<14>")
	)
	(segment
		(start 301.538894 -300.452028)
		(end 301.356014 -300.269148)
		(width 0.18288)
		(layer "In4.Cu")
		(net "M_B_CPU0_SA_DQ<14>")
	)
	(segment
		(start 316.154054 -293.94531)
		(end 315.92393 -294.175434)
		(width 0.18288)
		(layer "In4.Cu")
		(net "M_B_CPU0_SA_DQ<14>")
	)
	(segment
		(start 303.23282 -300.56074)
		(end 302.92548 -300.86808)
		(width 0.18288)
		(layer "In4.Cu")
		(net "M_B_CPU0_SA_DQ<14>")
	)
	(segment
		(start 338.732114 -271.335754)
		(end 338.726272 -271.33931)
		(width 0.088646)
		(layer "In4.Cu")
		(net "M_B_CPU0_SA_DQ<14>")
	)
	(segment
		(start 303.582324 -300.000416)
		(end 303.23282 -300.34992)
		(width 0.18288)
		(layer "In4.Cu")
		(net "M_B_CPU0_SA_DQ<14>")
	)
	(segment
		(start 318.084962 -292.68547)
		(end 318.084962 -292.944042)
		(width 0.18288)
		(layer "In4.Cu")
		(net "M_B_CPU0_SA_DQ<14>")
	)
	(segment
		(start 337.79587 -271.333722)
		(end 337.792314 -271.335754)
		(width 0.088646)
		(layer "In4.Cu")
		(net "M_B_CPU0_SA_DQ<14>")
	)
	(segment
		(start 313.027314 -295.369742)
		(end 312.711338 -295.685718)
		(width 0.18288)
		(layer "In4.Cu")
		(net "M_B_CPU0_SA_DQ<14>")
	)
	(segment
		(start 310.45531 -296.535094)
		(end 310.160416 -296.2402)
		(width 0.18288)
		(layer "In4.Cu")
		(net "M_B_CPU0_SA_DQ<14>")
	)
	(arc
		(start 337.792314 -271.335754)
		(mid 337.605006 -271.385897)
		(end 337.417664 -271.335754)
		(width 0.088646)
		(layer "In4.Cu")
		(net "M_B_CPU0_SA_DQ<14>")
	)
	(arc
		(start 336.846672 -271.33931)
		(mid 336.661817 -271.386228)
		(end 336.477864 -271.336008)
		(width 0.088646)
		(layer "In4.Cu")
		(net "M_B_CPU0_SA_DQ<14>")
	)
	(arc
		(start 335.538064 -271.335754)
		(mid 335.255362 -271.259978)
		(end 334.97266 -271.335754)
		(width 0.088646)
		(layer "In4.Cu")
		(net "M_B_CPU0_SA_DQ<14>")
	)
	(arc
		(start 333.750412 -271.825212)
		(mid 333.702733 -272.008112)
		(end 333.57185 -272.14449)
		(width 0.088646)
		(layer "In4.Cu")
		(net "M_B_CPU0_SA_DQ<14>")
	)
	(arc
		(start 339.297264 -271.336008)
		(mid 339.01809 -271.260209)
		(end 338.737956 -271.332452)
		(width 0.088646)
		(layer "In4.Cu")
		(net "M_B_CPU0_SA_DQ<14>")
	)
	(arc
		(start 341.176864 -271.336008)
		(mid 340.89769 -271.260209)
		(end 340.617556 -271.332452)
		(width 0.088646)
		(layer "In4.Cu")
		(net "M_B_CPU0_SA_DQ<14>")
	)
	(arc
		(start 338.357464 -271.336008)
		(mid 338.076983 -271.260202)
		(end 337.79587 -271.333722)
		(width 0.088646)
		(layer "In4.Cu")
		(net "M_B_CPU0_SA_DQ<14>")
	)
	(arc
		(start 339.666072 -271.33931)
		(mid 339.481217 -271.386228)
		(end 339.297264 -271.336008)
		(width 0.088646)
		(layer "In4.Cu")
		(net "M_B_CPU0_SA_DQ<14>")
	)
	(arc
		(start 340.237064 -271.336008)
		(mid 339.95789 -271.260209)
		(end 339.677756 -271.332452)
		(width 0.088646)
		(layer "In4.Cu")
		(net "M_B_CPU0_SA_DQ<14>")
	)
	(arc
		(start 333.56296 -272.14957)
		(mid 333.360674 -272.348551)
		(end 333.280512 -272.62074)
		(width 0.088646)
		(layer "In4.Cu")
		(net "M_B_CPU0_SA_DQ<14>")
	)
	(arc
		(start 341.834216 -271.825212)
		(mid 341.560258 -271.585013)
		(end 341.257382 -271.38249)
		(width 0.088646)
		(layer "In4.Cu")
		(net "M_B_CPU0_SA_DQ<14>")
	)
	(arc
		(start 336.477864 -271.335754)
		(mid 336.195162 -271.259978)
		(end 335.91246 -271.335754)
		(width 0.088646)
		(layer "In4.Cu")
		(net "M_B_CPU0_SA_DQ<14>")
	)
	(arc
		(start 340.605872 -271.33931)
		(mid 340.421017 -271.386228)
		(end 340.237064 -271.336008)
		(width 0.088646)
		(layer "In4.Cu")
		(net "M_B_CPU0_SA_DQ<14>")
	)
	(arc
		(start 334.598264 -271.335754)
		(mid 334.315562 -271.259978)
		(end 334.03286 -271.335754)
		(width 0.088646)
		(layer "In4.Cu")
		(net "M_B_CPU0_SA_DQ<14>")
	)
	(arc
		(start 334.03286 -271.335754)
		(mid 333.828525 -271.538359)
		(end 333.750412 -271.815306)
		(width 0.088646)
		(layer "In4.Cu")
		(net "M_B_CPU0_SA_DQ<14>")
	)
	(arc
		(start 334.97266 -271.335754)
		(mid 334.785462 -271.385897)
		(end 334.598264 -271.335754)
		(width 0.088646)
		(layer "In4.Cu")
		(net "M_B_CPU0_SA_DQ<14>")
	)
	(arc
		(start 337.417664 -271.335754)
		(mid 337.13772 -271.26011)
		(end 336.857086 -271.333214)
		(width 0.088646)
		(layer "In4.Cu")
		(net "M_B_CPU0_SA_DQ<14>")
	)
	(arc
		(start 338.726272 -271.33931)
		(mid 338.541417 -271.386228)
		(end 338.357464 -271.336008)
		(width 0.088646)
		(layer "In4.Cu")
		(net "M_B_CPU0_SA_DQ<14>")
	)
	(arc
		(start 333.280512 -272.647918)
		(mid 333.228242 -272.830283)
		(end 333.093314 -272.96364)
		(width 0.088646)
		(layer "In4.Cu")
		(net "M_B_CPU0_SA_DQ<14>")
	)
	(arc
		(start 335.91246 -271.335754)
		(mid 335.725262 -271.385897)
		(end 335.538064 -271.335754)
		(width 0.088646)
		(layer "In4.Cu")
		(net "M_B_CPU0_SA_DQ<14>")
	)
	(segment
		(start 291.735256 -298.891706)
		(end 291.556694 -298.891706)
		(width 0.20066)
		(layer "F.Cu")
		(net "M_B_CPU0_SA_DQ<13>")
	)
	(segment
		(start 291.556694 -298.891706)
		(end 291.225986 -298.891706)
		(width 0.101854)
		(layer "F.Cu")
		(net "M_B_CPU0_SA_DQ<13>")
	)
	(segment
		(start 291.225986 -298.891706)
		(end 289.240468 -298.891706)
		(width 0.1016)
		(layer "F.Cu")
		(net "M_B_CPU0_SA_DQ<13>")
	)
	(segment
		(start 287.801304 -299.527976)
		(end 287.589976 -299.316648)
		(width 0.20066)
		(layer "F.Cu")
		(net "M_B_CPU0_SA_DQ<13>")
	)
	(segment
		(start 288.62274 -298.882816)
		(end 288.46018 -299.045376)
		(width 0.20066)
		(layer "F.Cu")
		(net "M_B_CPU0_SA_DQ<13>")
	)
	(segment
		(start 289.240468 -298.891706)
		(end 289.231578 -298.882816)
		(width 0.1016)
		(layer "F.Cu")
		(net "M_B_CPU0_SA_DQ<13>")
	)
	(segment
		(start 294.904414 -299.316648)
		(end 293.799514 -299.316648)
		(width 0.20066)
		(layer "F.Cu")
		(net "M_B_CPU0_SA_DQ<13>")
	)
	(segment
		(start 288.46018 -299.373544)
		(end 288.305748 -299.527976)
		(width 0.20066)
		(layer "F.Cu")
		(net "M_B_CPU0_SA_DQ<13>")
	)
	(segment
		(start 287.589976 -299.316648)
		(end 286.255714 -299.316648)
		(width 0.20066)
		(layer "F.Cu")
		(net "M_B_CPU0_SA_DQ<13>")
	)
	(segment
		(start 288.46018 -299.045376)
		(end 288.46018 -299.373544)
		(width 0.20066)
		(layer "F.Cu")
		(net "M_B_CPU0_SA_DQ<13>")
	)
	(segment
		(start 340.424516 -270.475456)
		(end 340.424516 -271.011142)
		(width 0.20066)
		(layer "F.Cu")
		(net "M_B_CPU0_SA_DQ<13>")
	)
	(segment
		(start 288.305748 -299.527976)
		(end 287.801304 -299.527976)
		(width 0.20066)
		(layer "F.Cu")
		(net "M_B_CPU0_SA_DQ<13>")
	)
	(segment
		(start 340.424516 -271.011142)
		(end 340.424262 -271.011396)
		(width 0.20066)
		(layer "F.Cu")
		(net "M_B_CPU0_SA_DQ<13>")
	)
	(segment
		(start 293.799514 -299.316648)
		(end 292.160198 -299.316648)
		(width 0.20066)
		(layer "F.Cu")
		(net "M_B_CPU0_SA_DQ<13>")
	)
	(segment
		(start 289.231578 -298.882816)
		(end 288.62274 -298.882816)
		(width 0.20066)
		(layer "F.Cu")
		(net "M_B_CPU0_SA_DQ<13>")
	)
	(segment
		(start 292.160198 -299.316648)
		(end 291.735256 -298.891706)
		(width 0.20066)
		(layer "F.Cu")
		(net "M_B_CPU0_SA_DQ<13>")
	)
	(segment
		(start 336.857086 -270.689578)
		(end 336.852514 -270.687038)
		(width 0.088646)
		(layer "In4.Cu")
		(net "M_B_CPU0_SA_DQ<13>")
	)
	(segment
		(start 295.676828 -299.81779)
		(end 295.405556 -299.81779)
		(width 0.18288)
		(layer "In4.Cu")
		(net "M_B_CPU0_SA_DQ<13>")
	)
	(segment
		(start 297.932348 -299.924724)
		(end 297.932348 -300.181772)
		(width 0.18288)
		(layer "In4.Cu")
		(net "M_B_CPU0_SA_DQ<13>")
	)
	(segment
		(start 306.794662 -297.130216)
		(end 306.382166 -297.130216)
		(width 0.18288)
		(layer "In4.Cu")
		(net "M_B_CPU0_SA_DQ<13>")
	)
	(segment
		(start 310.327548 -295.476168)
		(end 310.134 -295.669716)
		(width 0.18288)
		(layer "In4.Cu")
		(net "M_B_CPU0_SA_DQ<13>")
	)
	(segment
		(start 296.733468 -299.741844)
		(end 296.550588 -299.924724)
		(width 0.18288)
		(layer "In4.Cu")
		(net "M_B_CPU0_SA_DQ<13>")
	)
	(segment
		(start 337.79587 -270.68907)
		(end 337.792314 -270.687038)
		(width 0.088646)
		(layer "In4.Cu")
		(net "M_B_CPU0_SA_DQ<13>")
	)
	(segment
		(start 296.042588 -300.364652)
		(end 295.859708 -300.181772)
		(width 0.18288)
		(layer "In4.Cu")
		(net "M_B_CPU0_SA_DQ<13>")
	)
	(segment
		(start 304.082196 -298.756578)
		(end 303.09693 -299.741844)
		(width 0.18288)
		(layer "In4.Cu")
		(net "M_B_CPU0_SA_DQ<13>")
	)
	(segment
		(start 297.241468 -300.181772)
		(end 297.241468 -299.924724)
		(width 0.18288)
		(layer "In4.Cu")
		(net "M_B_CPU0_SA_DQ<13>")
	)
	(segment
		(start 309.583074 -295.669716)
		(end 309.00497 -296.24782)
		(width 0.18288)
		(layer "In4.Cu")
		(net "M_B_CPU0_SA_DQ<13>")
	)
	(segment
		(start 331.443838 -273.575272)
		(end 322.687696 -282.331414)
		(width 0.18288)
		(layer "In4.Cu")
		(net "M_B_CPU0_SA_DQ<13>")
	)
	(segment
		(start 297.932348 -300.181772)
		(end 297.749468 -300.364652)
		(width 0.18288)
		(layer "In4.Cu")
		(net "M_B_CPU0_SA_DQ<13>")
	)
	(segment
		(start 295.859708 -300.181772)
		(end 295.859708 -300.00067)
		(width 0.18288)
		(layer "In4.Cu")
		(net "M_B_CPU0_SA_DQ<13>")
	)
	(segment
		(start 336.852514 -270.687038)
		(end 336.846672 -270.683736)
		(width 0.088646)
		(layer "In4.Cu")
		(net "M_B_CPU0_SA_DQ<13>")
	)
	(segment
		(start 298.115228 -299.741844)
		(end 297.932348 -299.924724)
		(width 0.18288)
		(layer "In4.Cu")
		(net "M_B_CPU0_SA_DQ<13>")
	)
	(segment
		(start 296.367708 -300.364652)
		(end 296.042588 -300.364652)
		(width 0.18288)
		(layer "In4.Cu")
		(net "M_B_CPU0_SA_DQ<13>")
	)
	(segment
		(start 307.920644 -296.24782)
		(end 307.504846 -296.420032)
		(width 0.18288)
		(layer "In4.Cu")
		(net "M_B_CPU0_SA_DQ<13>")
	)
	(segment
		(start 314.675266 -294.695626)
		(end 312.933842 -294.695626)
		(width 0.18288)
		(layer "In4.Cu")
		(net "M_B_CPU0_SA_DQ<13>")
	)
	(segment
		(start 296.550588 -300.181772)
		(end 296.367708 -300.364652)
		(width 0.18288)
		(layer "In4.Cu")
		(net "M_B_CPU0_SA_DQ<13>")
	)
	(segment
		(start 333.580486 -270.746474)
		(end 333.424276 -270.902684)
		(width 0.088646)
		(layer "In4.Cu")
		(net "M_B_CPU0_SA_DQ<13>")
	)
	(segment
		(start 333.424276 -270.902684)
		(end 333.424276 -271.594834)
		(width 0.088646)
		(layer "In4.Cu")
		(net "M_B_CPU0_SA_DQ<13>")
	)
	(segment
		(start 340.616794 -270.689832)
		(end 340.611714 -270.687038)
		(width 0.088646)
		(layer "In4.Cu")
		(net "M_B_CPU0_SA_DQ<13>")
	)
	(segment
		(start 340.424262 -271.011396)
		(end 340.73719 -271.011396)
		(width 0.088646)
		(layer "In4.Cu")
		(net "M_B_CPU0_SA_DQ<13>")
	)
	(segment
		(start 297.424348 -300.364652)
		(end 297.241468 -300.181772)
		(width 0.18288)
		(layer "In4.Cu")
		(net "M_B_CPU0_SA_DQ<13>")
	)
	(segment
		(start 339.677756 -270.69034)
		(end 339.666072 -270.683736)
		(width 0.088646)
		(layer "In4.Cu")
		(net "M_B_CPU0_SA_DQ<13>")
	)
	(segment
		(start 312.1533 -295.476168)
		(end 310.327548 -295.476168)
		(width 0.18288)
		(layer "In4.Cu")
		(net "M_B_CPU0_SA_DQ<13>")
	)
	(segment
		(start 309.00497 -296.24782)
		(end 307.920644 -296.24782)
		(width 0.18288)
		(layer "In4.Cu")
		(net "M_B_CPU0_SA_DQ<13>")
	)
	(segment
		(start 310.134 -295.669716)
		(end 309.583074 -295.669716)
		(width 0.18288)
		(layer "In4.Cu")
		(net "M_B_CPU0_SA_DQ<13>")
	)
	(segment
		(start 306.382166 -297.130216)
		(end 304.755804 -298.756578)
		(width 0.18288)
		(layer "In4.Cu")
		(net "M_B_CPU0_SA_DQ<13>")
	)
	(segment
		(start 297.241468 -299.924724)
		(end 297.058588 -299.741844)
		(width 0.18288)
		(layer "In4.Cu")
		(net "M_B_CPU0_SA_DQ<13>")
	)
	(segment
		(start 333.424276 -271.594834)
		(end 332.397608 -272.621502)
		(width 0.088646)
		(layer "In4.Cu")
		(net "M_B_CPU0_SA_DQ<13>")
	)
	(segment
		(start 332.006194 -273.2659)
		(end 331.696822 -273.575272)
		(width 0.18288)
		(layer "In4.Cu")
		(net "M_B_CPU0_SA_DQ<13>")
	)
	(segment
		(start 295.859708 -300.00067)
		(end 295.676828 -299.81779)
		(width 0.18288)
		(layer "In4.Cu")
		(net "M_B_CPU0_SA_DQ<13>")
	)
	(segment
		(start 307.504846 -296.420032)
		(end 306.794662 -297.130216)
		(width 0.18288)
		(layer "In4.Cu")
		(net "M_B_CPU0_SA_DQ<13>")
	)
	(segment
		(start 322.687696 -282.331414)
		(end 319.610486 -289.760406)
		(width 0.18288)
		(layer "In4.Cu")
		(net "M_B_CPU0_SA_DQ<13>")
	)
	(segment
		(start 340.73719 -271.011396)
		(end 340.794594 -270.953992)
		(width 0.088646)
		(layer "In4.Cu")
		(net "M_B_CPU0_SA_DQ<13>")
	)
	(segment
		(start 333.580486 -270.74622)
		(end 333.580486 -270.746474)
		(width 0.088646)
		(layer "In4.Cu")
		(net "M_B_CPU0_SA_DQ<13>")
	)
	(segment
		(start 296.550588 -299.924724)
		(end 296.550588 -300.181772)
		(width 0.18288)
		(layer "In4.Cu")
		(net "M_B_CPU0_SA_DQ<13>")
	)
	(segment
		(start 319.610486 -289.760406)
		(end 314.675266 -294.695626)
		(width 0.18288)
		(layer "In4.Cu")
		(net "M_B_CPU0_SA_DQ<13>")
	)
	(segment
		(start 303.09693 -299.741844)
		(end 298.115228 -299.741844)
		(width 0.18288)
		(layer "In4.Cu")
		(net "M_B_CPU0_SA_DQ<13>")
	)
	(segment
		(start 297.058588 -299.741844)
		(end 296.733468 -299.741844)
		(width 0.18288)
		(layer "In4.Cu")
		(net "M_B_CPU0_SA_DQ<13>")
	)
	(segment
		(start 295.405556 -299.81779)
		(end 294.904414 -299.316648)
		(width 0.18288)
		(layer "In4.Cu")
		(net "M_B_CPU0_SA_DQ<13>")
	)
	(segment
		(start 312.933842 -294.695626)
		(end 312.1533 -295.476168)
		(width 0.18288)
		(layer "In4.Cu")
		(net "M_B_CPU0_SA_DQ<13>")
	)
	(segment
		(start 332.397608 -272.621502)
		(end 332.397608 -272.874486)
		(width 0.088646)
		(layer "In4.Cu")
		(net "M_B_CPU0_SA_DQ<13>")
	)
	(segment
		(start 335.91627 -270.68907)
		(end 335.91246 -270.687038)
		(width 0.088646)
		(layer "In4.Cu")
		(net "M_B_CPU0_SA_DQ<13>")
	)
	(segment
		(start 297.749468 -300.364652)
		(end 297.424348 -300.364652)
		(width 0.18288)
		(layer "In4.Cu")
		(net "M_B_CPU0_SA_DQ<13>")
	)
	(segment
		(start 331.696822 -273.575272)
		(end 331.443838 -273.575272)
		(width 0.18288)
		(layer "In4.Cu")
		(net "M_B_CPU0_SA_DQ<13>")
	)
	(segment
		(start 340.611714 -270.687038)
		(end 340.605872 -270.683736)
		(width 0.088646)
		(layer "In4.Cu")
		(net "M_B_CPU0_SA_DQ<13>")
	)
	(segment
		(start 304.755804 -298.756578)
		(end 304.082196 -298.756578)
		(width 0.18288)
		(layer "In4.Cu")
		(net "M_B_CPU0_SA_DQ<13>")
	)
	(segment
		(start 332.397608 -272.874486)
		(end 332.006194 -273.2659)
		(width 0.088646)
		(layer "In4.Cu")
		(net "M_B_CPU0_SA_DQ<13>")
	)
	(segment
		(start 338.737956 -270.69034)
		(end 338.726272 -270.683736)
		(width 0.088646)
		(layer "In4.Cu")
		(net "M_B_CPU0_SA_DQ<13>")
	)
	(arc
		(start 338.357464 -270.687038)
		(mid 338.076953 -270.762684)
		(end 337.79587 -270.68907)
		(width 0.088646)
		(layer "In4.Cu")
		(net "M_B_CPU0_SA_DQ<13>")
	)
	(arc
		(start 340.794594 -270.953992)
		(mid 340.735129 -270.802105)
		(end 340.616794 -270.689832)
		(width 0.088646)
		(layer "In4.Cu")
		(net "M_B_CPU0_SA_DQ<13>")
	)
	(arc
		(start 340.237064 -270.687038)
		(mid 339.957861 -270.762678)
		(end 339.677756 -270.69034)
		(width 0.088646)
		(layer "In4.Cu")
		(net "M_B_CPU0_SA_DQ<13>")
	)
	(arc
		(start 334.97266 -270.687038)
		(mid 334.785462 -270.636895)
		(end 334.598264 -270.687038)
		(width 0.088646)
		(layer "In4.Cu")
		(net "M_B_CPU0_SA_DQ<13>")
	)
	(arc
		(start 335.538064 -270.687038)
		(mid 335.255362 -270.762814)
		(end 334.97266 -270.687038)
		(width 0.088646)
		(layer "In4.Cu")
		(net "M_B_CPU0_SA_DQ<13>")
	)
	(arc
		(start 334.598264 -270.687038)
		(mid 334.315562 -270.762814)
		(end 334.03286 -270.687038)
		(width 0.088646)
		(layer "In4.Cu")
		(net "M_B_CPU0_SA_DQ<13>")
	)
	(arc
		(start 339.297264 -270.687038)
		(mid 339.018061 -270.762678)
		(end 338.737956 -270.69034)
		(width 0.088646)
		(layer "In4.Cu")
		(net "M_B_CPU0_SA_DQ<13>")
	)
	(arc
		(start 336.477864 -270.687038)
		(mid 336.197353 -270.762684)
		(end 335.91627 -270.68907)
		(width 0.088646)
		(layer "In4.Cu")
		(net "M_B_CPU0_SA_DQ<13>")
	)
	(arc
		(start 340.605872 -270.683736)
		(mid 340.421017 -270.636786)
		(end 340.237064 -270.687038)
		(width 0.088646)
		(layer "In4.Cu")
		(net "M_B_CPU0_SA_DQ<13>")
	)
	(arc
		(start 336.846672 -270.683736)
		(mid 336.661817 -270.636786)
		(end 336.477864 -270.687038)
		(width 0.088646)
		(layer "In4.Cu")
		(net "M_B_CPU0_SA_DQ<13>")
	)
	(arc
		(start 337.792314 -270.687038)
		(mid 337.605006 -270.636895)
		(end 337.417664 -270.687038)
		(width 0.088646)
		(layer "In4.Cu")
		(net "M_B_CPU0_SA_DQ<13>")
	)
	(arc
		(start 338.726272 -270.683736)
		(mid 338.541417 -270.636786)
		(end 338.357464 -270.687038)
		(width 0.088646)
		(layer "In4.Cu")
		(net "M_B_CPU0_SA_DQ<13>")
	)
	(arc
		(start 335.91246 -270.687038)
		(mid 335.725262 -270.636895)
		(end 335.538064 -270.687038)
		(width 0.088646)
		(layer "In4.Cu")
		(net "M_B_CPU0_SA_DQ<13>")
	)
	(arc
		(start 337.417664 -270.687038)
		(mid 337.13772 -270.762682)
		(end 336.857086 -270.689578)
		(width 0.088646)
		(layer "In4.Cu")
		(net "M_B_CPU0_SA_DQ<13>")
	)
	(arc
		(start 334.03286 -270.687038)
		(mid 333.845662 -270.636895)
		(end 333.658464 -270.687038)
		(width 0.088646)
		(layer "In4.Cu")
		(net "M_B_CPU0_SA_DQ<13>")
	)
	(arc
		(start 339.666072 -270.683736)
		(mid 339.481217 -270.636786)
		(end 339.297264 -270.687038)
		(width 0.088646)
		(layer "In4.Cu")
		(net "M_B_CPU0_SA_DQ<13>")
	)
	(arc
		(start 333.658464 -270.687038)
		(mid 333.617534 -270.714071)
		(end 333.580486 -270.74622)
		(width 0.088646)
		(layer "In4.Cu")
		(net "M_B_CPU0_SA_DQ<13>")
	)
	(segment
		(start 288.46018 -301.08271)
		(end 288.28746 -301.25543)
		(width 0.20066)
		(layer "F.Cu")
		(net "M_B_CPU0_SA_DQ<12>")
	)
	(segment
		(start 289.231578 -300.5836)
		(end 288.66973 -300.5836)
		(width 0.20066)
		(layer "F.Cu")
		(net "M_B_CPU0_SA_DQ<12>")
	)
	(segment
		(start 288.46018 -300.79315)
		(end 288.46018 -301.08271)
		(width 0.20066)
		(layer "F.Cu")
		(net "M_B_CPU0_SA_DQ<12>")
	)
	(segment
		(start 292.005512 -300.591728)
		(end 291.556694 -300.591728)
		(width 0.20066)
		(layer "F.Cu")
		(net "M_B_CPU0_SA_DQ<12>")
	)
	(segment
		(start 291.556694 -300.591728)
		(end 289.48761 -300.591728)
		(width 0.1016)
		(layer "F.Cu")
		(net "M_B_CPU0_SA_DQ<12>")
	)
	(segment
		(start 288.66973 -300.5836)
		(end 288.46018 -300.79315)
		(width 0.20066)
		(layer "F.Cu")
		(net "M_B_CPU0_SA_DQ<12>")
	)
	(segment
		(start 294.904414 -301.01667)
		(end 293.799514 -301.01667)
		(width 0.20066)
		(layer "F.Cu")
		(net "M_B_CPU0_SA_DQ<12>")
	)
	(segment
		(start 292.430454 -301.01667)
		(end 292.005512 -300.591728)
		(width 0.20066)
		(layer "F.Cu")
		(net "M_B_CPU0_SA_DQ<12>")
	)
	(segment
		(start 289.48761 -300.591728)
		(end 289.239706 -300.591728)
		(width 0.101854)
		(layer "F.Cu")
		(net "M_B_CPU0_SA_DQ<12>")
	)
	(segment
		(start 293.799514 -301.01667)
		(end 292.430454 -301.01667)
		(width 0.20066)
		(layer "F.Cu")
		(net "M_B_CPU0_SA_DQ<12>")
	)
	(segment
		(start 339.954362 -271.289272)
		(end 339.954616 -271.289526)
		(width 0.20066)
		(layer "F.Cu")
		(net "M_B_CPU0_SA_DQ<12>")
	)
	(segment
		(start 288.28746 -301.25543)
		(end 287.828736 -301.25543)
		(width 0.20066)
		(layer "F.Cu")
		(net "M_B_CPU0_SA_DQ<12>")
	)
	(segment
		(start 287.589976 -301.01667)
		(end 286.255714 -301.01667)
		(width 0.20066)
		(layer "F.Cu")
		(net "M_B_CPU0_SA_DQ<12>")
	)
	(segment
		(start 289.239706 -300.591728)
		(end 289.231578 -300.5836)
		(width 0.101854)
		(layer "F.Cu")
		(net "M_B_CPU0_SA_DQ<12>")
	)
	(segment
		(start 287.828736 -301.25543)
		(end 287.589976 -301.01667)
		(width 0.20066)
		(layer "F.Cu")
		(net "M_B_CPU0_SA_DQ<12>")
	)
	(segment
		(start 339.954616 -271.289526)
		(end 339.954616 -271.825212)
		(width 0.20066)
		(layer "F.Cu")
		(net "M_B_CPU0_SA_DQ<12>")
	)
	(segment
		(start 310.60644 -297.69308)
		(end 310.16448 -297.25112)
		(width 0.18288)
		(layer "In4.Cu")
		(net "M_B_CPU0_SA_DQ<12>")
	)
	(segment
		(start 296.20337 -301.852584)
		(end 296.20337 -301.624746)
		(width 0.18288)
		(layer "In4.Cu")
		(net "M_B_CPU0_SA_DQ<12>")
	)
	(segment
		(start 306.890674 -298.721526)
		(end 306.51831 -298.721526)
		(width 0.18288)
		(layer "In4.Cu")
		(net "M_B_CPU0_SA_DQ<12>")
	)
	(segment
		(start 297.59021 -301.624746)
		(end 297.40733 -301.441866)
		(width 0.18288)
		(layer "In4.Cu")
		(net "M_B_CPU0_SA_DQ<12>")
	)
	(segment
		(start 308.412388 -297.875198)
		(end 307.737002 -297.875198)
		(width 0.18288)
		(layer "In4.Cu")
		(net "M_B_CPU0_SA_DQ<12>")
	)
	(segment
		(start 296.89679 -301.624746)
		(end 296.89679 -301.852584)
		(width 0.18288)
		(layer "In4.Cu")
		(net "M_B_CPU0_SA_DQ<12>")
	)
	(segment
		(start 337.891882 -271.498314)
		(end 337.887564 -271.500854)
		(width 0.088646)
		(layer "In4.Cu")
		(net "M_B_CPU0_SA_DQ<12>")
	)
	(segment
		(start 331.741272 -274.777962)
		(end 323.539358 -282.979876)
		(width 0.18288)
		(layer "In4.Cu")
		(net "M_B_CPU0_SA_DQ<12>")
	)
	(segment
		(start 304.705512 -300.534324)
		(end 304.131472 -300.534324)
		(width 0.18288)
		(layer "In4.Cu")
		(net "M_B_CPU0_SA_DQ<12>")
	)
	(segment
		(start 297.40733 -301.441866)
		(end 297.07967 -301.441866)
		(width 0.18288)
		(layer "In4.Cu")
		(net "M_B_CPU0_SA_DQ<12>")
	)
	(segment
		(start 309.490618 -297.567096)
		(end 308.72049 -297.567096)
		(width 0.18288)
		(layer "In4.Cu")
		(net "M_B_CPU0_SA_DQ<12>")
	)
	(segment
		(start 300.97095 -301.736252)
		(end 300.676564 -301.441866)
		(width 0.18288)
		(layer "In4.Cu")
		(net "M_B_CPU0_SA_DQ<12>")
	)
	(segment
		(start 333.471266 -272.630646)
		(end 333.471266 -272.649188)
		(width 0.088646)
		(layer "In4.Cu")
		(net "M_B_CPU0_SA_DQ<12>")
	)
	(segment
		(start 296.71391 -302.035464)
		(end 296.38625 -302.035464)
		(width 0.18288)
		(layer "In4.Cu")
		(net "M_B_CPU0_SA_DQ<12>")
	)
	(segment
		(start 298.28363 -301.624746)
		(end 298.28363 -301.852584)
		(width 0.18288)
		(layer "In4.Cu")
		(net "M_B_CPU0_SA_DQ<12>")
	)
	(segment
		(start 338.833206 -271.497552)
		(end 338.827364 -271.500854)
		(width 0.088646)
		(layer "In4.Cu")
		(net "M_B_CPU0_SA_DQ<12>")
	)
	(segment
		(start 307.737002 -297.875198)
		(end 306.890674 -298.721526)
		(width 0.18288)
		(layer "In4.Cu")
		(net "M_B_CPU0_SA_DQ<12>")
	)
	(segment
		(start 300.676564 -301.441866)
		(end 298.46651 -301.441866)
		(width 0.18288)
		(layer "In4.Cu")
		(net "M_B_CPU0_SA_DQ<12>")
	)
	(segment
		(start 339.954616 -271.825212)
		(end 339.954362 -271.824958)
		(width 0.088646)
		(layer "In4.Cu")
		(net "M_B_CPU0_SA_DQ<12>")
	)
	(segment
		(start 336.947764 -271.500854)
		(end 336.941922 -271.50441)
		(width 0.088646)
		(layer "In4.Cu")
		(net "M_B_CPU0_SA_DQ<12>")
	)
	(segment
		(start 332.90637 -273.44497)
		(end 332.90637 -273.612864)
		(width 0.088646)
		(layer "In4.Cu")
		(net "M_B_CPU0_SA_DQ<12>")
	)
	(segment
		(start 315.47943 -296.361358)
		(end 313.204098 -296.361358)
		(width 0.18288)
		(layer "In4.Cu")
		(net "M_B_CPU0_SA_DQ<12>")
	)
	(segment
		(start 339.59927 -271.729962)
		(end 339.202014 -271.500854)
		(width 0.088646)
		(layer "In4.Cu")
		(net "M_B_CPU0_SA_DQ<12>")
	)
	(segment
		(start 306.51831 -298.721526)
		(end 304.705512 -300.534324)
		(width 0.18288)
		(layer "In4.Cu")
		(net "M_B_CPU0_SA_DQ<12>")
	)
	(segment
		(start 312.497216 -297.06824)
		(end 311.696608 -297.06824)
		(width 0.18288)
		(layer "In4.Cu")
		(net "M_B_CPU0_SA_DQ<12>")
	)
	(segment
		(start 297.59021 -301.852584)
		(end 297.59021 -301.624746)
		(width 0.18288)
		(layer "In4.Cu")
		(net "M_B_CPU0_SA_DQ<12>")
	)
	(segment
		(start 332.90637 -273.612864)
		(end 331.741272 -274.777962)
		(width 0.088646)
		(layer "In4.Cu")
		(net "M_B_CPU0_SA_DQ<12>")
	)
	(segment
		(start 301.367444 -301.736252)
		(end 300.97095 -301.736252)
		(width 0.18288)
		(layer "In4.Cu")
		(net "M_B_CPU0_SA_DQ<12>")
	)
	(segment
		(start 333.300832 -273.050508)
		(end 332.90637 -273.44497)
		(width 0.088646)
		(layer "In4.Cu")
		(net "M_B_CPU0_SA_DQ<12>")
	)
	(segment
		(start 298.10075 -302.035464)
		(end 297.77309 -302.035464)
		(width 0.18288)
		(layer "In4.Cu")
		(net "M_B_CPU0_SA_DQ<12>")
	)
	(segment
		(start 298.28363 -301.852584)
		(end 298.10075 -302.035464)
		(width 0.18288)
		(layer "In4.Cu")
		(net "M_B_CPU0_SA_DQ<12>")
	)
	(segment
		(start 296.89679 -301.852584)
		(end 296.71391 -302.035464)
		(width 0.18288)
		(layer "In4.Cu")
		(net "M_B_CPU0_SA_DQ<12>")
	)
	(segment
		(start 296.20337 -301.624746)
		(end 296.02049 -301.441866)
		(width 0.18288)
		(layer "In4.Cu")
		(net "M_B_CPU0_SA_DQ<12>")
	)
	(segment
		(start 336.382614 -271.500854)
		(end 336.38236 -271.500854)
		(width 0.088646)
		(layer "In4.Cu")
		(net "M_B_CPU0_SA_DQ<12>")
	)
	(segment
		(start 298.46651 -301.441866)
		(end 298.28363 -301.624746)
		(width 0.18288)
		(layer "In4.Cu")
		(net "M_B_CPU0_SA_DQ<12>")
	)
	(segment
		(start 297.07967 -301.441866)
		(end 296.89679 -301.624746)
		(width 0.18288)
		(layer "In4.Cu")
		(net "M_B_CPU0_SA_DQ<12>")
	)
	(segment
		(start 310.16448 -297.25112)
		(end 309.806594 -297.25112)
		(width 0.18288)
		(layer "In4.Cu")
		(net "M_B_CPU0_SA_DQ<12>")
	)
	(segment
		(start 311.071768 -297.69308)
		(end 310.60644 -297.69308)
		(width 0.18288)
		(layer "In4.Cu")
		(net "M_B_CPU0_SA_DQ<12>")
	)
	(segment
		(start 313.204098 -296.361358)
		(end 312.497216 -297.06824)
		(width 0.18288)
		(layer "In4.Cu")
		(net "M_B_CPU0_SA_DQ<12>")
	)
	(segment
		(start 338.827364 -271.500854)
		(end 338.821522 -271.50441)
		(width 0.088646)
		(layer "In4.Cu")
		(net "M_B_CPU0_SA_DQ<12>")
	)
	(segment
		(start 295.32961 -301.441866)
		(end 294.904414 -301.01667)
		(width 0.18288)
		(layer "In4.Cu")
		(net "M_B_CPU0_SA_DQ<12>")
	)
	(segment
		(start 301.66183 -301.441866)
		(end 301.367444 -301.736252)
		(width 0.18288)
		(layer "In4.Cu")
		(net "M_B_CPU0_SA_DQ<12>")
	)
	(segment
		(start 296.38625 -302.035464)
		(end 296.20337 -301.852584)
		(width 0.18288)
		(layer "In4.Cu")
		(net "M_B_CPU0_SA_DQ<12>")
	)
	(segment
		(start 333.940912 -271.825212)
		(end 333.940912 -271.843754)
		(width 0.088646)
		(layer "In4.Cu")
		(net "M_B_CPU0_SA_DQ<12>")
	)
	(segment
		(start 297.77309 -302.035464)
		(end 297.59021 -301.852584)
		(width 0.18288)
		(layer "In4.Cu")
		(net "M_B_CPU0_SA_DQ<12>")
	)
	(segment
		(start 296.02049 -301.441866)
		(end 295.32961 -301.441866)
		(width 0.18288)
		(layer "In4.Cu")
		(net "M_B_CPU0_SA_DQ<12>")
	)
	(segment
		(start 319.776348 -292.06444)
		(end 315.47943 -296.361358)
		(width 0.18288)
		(layer "In4.Cu")
		(net "M_B_CPU0_SA_DQ<12>")
	)
	(segment
		(start 323.539358 -282.979876)
		(end 319.776348 -292.06444)
		(width 0.18288)
		(layer "In4.Cu")
		(net "M_B_CPU0_SA_DQ<12>")
	)
	(segment
		(start 303.22393 -301.441866)
		(end 301.66183 -301.441866)
		(width 0.18288)
		(layer "In4.Cu")
		(net "M_B_CPU0_SA_DQ<12>")
	)
	(segment
		(start 336.951574 -271.498822)
		(end 336.947764 -271.500854)
		(width 0.088646)
		(layer "In4.Cu")
		(net "M_B_CPU0_SA_DQ<12>")
	)
	(segment
		(start 304.131472 -300.534324)
		(end 303.22393 -301.441866)
		(width 0.18288)
		(layer "In4.Cu")
		(net "M_B_CPU0_SA_DQ<12>")
	)
	(segment
		(start 334.128364 -271.500854)
		(end 334.119474 -271.505934)
		(width 0.088646)
		(layer "In4.Cu")
		(net "M_B_CPU0_SA_DQ<12>")
	)
	(segment
		(start 311.696608 -297.06824)
		(end 311.071768 -297.69308)
		(width 0.18288)
		(layer "In4.Cu")
		(net "M_B_CPU0_SA_DQ<12>")
	)
	(segment
		(start 309.806594 -297.25112)
		(end 309.490618 -297.567096)
		(width 0.18288)
		(layer "In4.Cu")
		(net "M_B_CPU0_SA_DQ<12>")
	)
	(segment
		(start 308.72049 -297.567096)
		(end 308.412388 -297.875198)
		(width 0.18288)
		(layer "In4.Cu")
		(net "M_B_CPU0_SA_DQ<12>")
	)
	(arc
		(start 335.44256 -271.500854)
		(mid 335.255362 -271.450711)
		(end 335.068164 -271.500854)
		(width 0.088646)
		(layer "In4.Cu")
		(net "M_B_CPU0_SA_DQ<12>")
	)
	(arc
		(start 339.202014 -271.500854)
		(mid 339.01806 -271.450725)
		(end 338.833206 -271.497552)
		(width 0.088646)
		(layer "In4.Cu")
		(net "M_B_CPU0_SA_DQ<12>")
	)
	(arc
		(start 335.068164 -271.500854)
		(mid 334.785462 -271.57663)
		(end 334.50276 -271.500854)
		(width 0.088646)
		(layer "In4.Cu")
		(net "M_B_CPU0_SA_DQ<12>")
	)
	(arc
		(start 337.887564 -271.500854)
		(mid 337.605006 -271.576503)
		(end 337.322414 -271.500854)
		(width 0.088646)
		(layer "In4.Cu")
		(net "M_B_CPU0_SA_DQ<12>")
	)
	(arc
		(start 333.940912 -271.843754)
		(mid 333.86075 -272.115943)
		(end 333.658464 -272.314924)
		(width 0.088646)
		(layer "In4.Cu")
		(net "M_B_CPU0_SA_DQ<12>")
	)
	(arc
		(start 336.007964 -271.500854)
		(mid 335.725262 -271.57663)
		(end 335.44256 -271.500854)
		(width 0.088646)
		(layer "In4.Cu")
		(net "M_B_CPU0_SA_DQ<12>")
	)
	(arc
		(start 334.50276 -271.500854)
		(mid 334.315562 -271.450711)
		(end 334.128364 -271.500854)
		(width 0.088646)
		(layer "In4.Cu")
		(net "M_B_CPU0_SA_DQ<12>")
	)
	(arc
		(start 338.262214 -271.500854)
		(mid 338.077377 -271.450593)
		(end 337.891882 -271.498314)
		(width 0.088646)
		(layer "In4.Cu")
		(net "M_B_CPU0_SA_DQ<12>")
	)
	(arc
		(start 339.954362 -271.824958)
		(mid 339.770555 -271.800846)
		(end 339.59927 -271.729962)
		(width 0.088646)
		(layer "In4.Cu")
		(net "M_B_CPU0_SA_DQ<12>")
	)
	(arc
		(start 336.941922 -271.50441)
		(mid 336.661787 -271.576693)
		(end 336.382614 -271.500854)
		(width 0.088646)
		(layer "In4.Cu")
		(net "M_B_CPU0_SA_DQ<12>")
	)
	(arc
		(start 333.471266 -272.649188)
		(mid 333.425088 -272.866436)
		(end 333.300832 -273.050508)
		(width 0.088646)
		(layer "In4.Cu")
		(net "M_B_CPU0_SA_DQ<12>")
	)
	(arc
		(start 334.119474 -271.505934)
		(mid 333.98856 -271.642294)
		(end 333.940912 -271.825212)
		(width 0.088646)
		(layer "In4.Cu")
		(net "M_B_CPU0_SA_DQ<12>")
	)
	(arc
		(start 336.38236 -271.500854)
		(mid 336.195162 -271.450711)
		(end 336.007964 -271.500854)
		(width 0.088646)
		(layer "In4.Cu")
		(net "M_B_CPU0_SA_DQ<12>")
	)
	(arc
		(start 337.322414 -271.500854)
		(mid 337.137264 -271.450716)
		(end 336.951574 -271.498822)
		(width 0.088646)
		(layer "In4.Cu")
		(net "M_B_CPU0_SA_DQ<12>")
	)
	(arc
		(start 338.821522 -271.50441)
		(mid 338.541387 -271.576693)
		(end 338.262214 -271.500854)
		(width 0.088646)
		(layer "In4.Cu")
		(net "M_B_CPU0_SA_DQ<12>")
	)
	(arc
		(start 333.658464 -272.314924)
		(mid 333.523531 -272.448278)
		(end 333.471266 -272.630646)
		(width 0.088646)
		(layer "In4.Cu")
		(net "M_B_CPU0_SA_DQ<12>")
	)
	(segment
		(start 295.544748 -304.841656)
		(end 295.000426 -304.841656)
		(width 0.20066)
		(layer "F.Cu")
		(net "M_B_CPU0_SA_DQ<11>")
	)
	(segment
		(start 292.321488 -304.85588)
		(end 292.178994 -304.713386)
		(width 0.20066)
		(layer "F.Cu")
		(net "M_B_CPU0_SA_DQ<11>")
	)
	(segment
		(start 292.67531 -304.85588)
		(end 292.321488 -304.85588)
		(width 0.20066)
		(layer "F.Cu")
		(net "M_B_CPU0_SA_DQ<11>")
	)
	(segment
		(start 295.000426 -304.841656)
		(end 292.927532 -304.841656)
		(width 0.1016)
		(layer "F.Cu")
		(net "M_B_CPU0_SA_DQ<11>")
	)
	(segment
		(start 296.217594 -304.412396)
		(end 295.82237 -304.412396)
		(width 0.20066)
		(layer "F.Cu")
		(net "M_B_CPU0_SA_DQ<11>")
	)
	(segment
		(start 296.875962 -304.624232)
		(end 296.42943 -304.624232)
		(width 0.20066)
		(layer "F.Cu")
		(net "M_B_CPU0_SA_DQ<11>")
	)
	(segment
		(start 295.693846 -304.692558)
		(end 295.544748 -304.841656)
		(width 0.20066)
		(layer "F.Cu")
		(net "M_B_CPU0_SA_DQ<11>")
	)
	(segment
		(start 292.689534 -304.841656)
		(end 292.67531 -304.85588)
		(width 0.101854)
		(layer "F.Cu")
		(net "M_B_CPU0_SA_DQ<11>")
	)
	(segment
		(start 295.693846 -304.54092)
		(end 295.693846 -304.692558)
		(width 0.20066)
		(layer "F.Cu")
		(net "M_B_CPU0_SA_DQ<11>")
	)
	(segment
		(start 292.05301 -304.416714)
		(end 290.355782 -304.416714)
		(width 0.20066)
		(layer "F.Cu")
		(net "M_B_CPU0_SA_DQ<11>")
	)
	(segment
		(start 292.927532 -304.841656)
		(end 292.689534 -304.841656)
		(width 0.101854)
		(layer "F.Cu")
		(net "M_B_CPU0_SA_DQ<11>")
	)
	(segment
		(start 296.42943 -304.624232)
		(end 296.217594 -304.412396)
		(width 0.20066)
		(layer "F.Cu")
		(net "M_B_CPU0_SA_DQ<11>")
	)
	(segment
		(start 299.029882 -304.416714)
		(end 297.899582 -304.416714)
		(width 0.20066)
		(layer "F.Cu")
		(net "M_B_CPU0_SA_DQ<11>")
	)
	(segment
		(start 297.899582 -304.416714)
		(end 297.08348 -304.416714)
		(width 0.20066)
		(layer "F.Cu")
		(net "M_B_CPU0_SA_DQ<11>")
	)
	(segment
		(start 292.178994 -304.542698)
		(end 292.05301 -304.416714)
		(width 0.20066)
		(layer "F.Cu")
		(net "M_B_CPU0_SA_DQ<11>")
	)
	(segment
		(start 292.178994 -304.713386)
		(end 292.178994 -304.542698)
		(width 0.20066)
		(layer "F.Cu")
		(net "M_B_CPU0_SA_DQ<11>")
	)
	(segment
		(start 297.08348 -304.416714)
		(end 296.875962 -304.624232)
		(width 0.20066)
		(layer "F.Cu")
		(net "M_B_CPU0_SA_DQ<11>")
	)
	(segment
		(start 295.82237 -304.412396)
		(end 295.693846 -304.54092)
		(width 0.20066)
		(layer "F.Cu")
		(net "M_B_CPU0_SA_DQ<11>")
	)
	(arc
		(start 341.833962 -272.917158)
		(mid 341.834025 -273.185128)
		(end 341.834216 -273.453098)
		(width 0.20066)
		(layer "F.Cu")
		(net "M_B_CPU0_SA_DQ<11>")
	)
	(segment
		(start 325.367142 -285.18612)
		(end 321.982084 -293.357808)
		(width 0.18288)
		(layer "In4.Cu")
		(net "M_B_CPU0_SA_DQ<11>")
	)
	(segment
		(start 308.571646 -302.234854)
		(end 307.918104 -302.888396)
		(width 0.18288)
		(layer "In4.Cu")
		(net "M_B_CPU0_SA_DQ<11>")
	)
	(segment
		(start 333.750412 -276.693122)
		(end 333.750412 -276.708616)
		(width 0.088646)
		(layer "In4.Cu")
		(net "M_B_CPU0_SA_DQ<11>")
	)
	(segment
		(start 301.66183 -304.506884)
		(end 301.50181 -304.346864)
		(width 0.18288)
		(layer "In4.Cu")
		(net "M_B_CPU0_SA_DQ<11>")
	)
	(segment
		(start 304.86604 -304.03927)
		(end 303.82718 -304.03927)
		(width 0.18288)
		(layer "In4.Cu")
		(net "M_B_CPU0_SA_DQ<11>")
	)
	(segment
		(start 333.57185 -277.027894)
		(end 333.56296 -277.032974)
		(width 0.088646)
		(layer "In4.Cu")
		(net "M_B_CPU0_SA_DQ<11>")
	)
	(segment
		(start 341.478616 -273.357848)
		(end 341.081614 -273.12874)
		(width 0.088646)
		(layer "In4.Cu")
		(net "M_B_CPU0_SA_DQ<11>")
	)
	(segment
		(start 307.692044 -302.888396)
		(end 307.389784 -302.586136)
		(width 0.18288)
		(layer "In4.Cu")
		(net "M_B_CPU0_SA_DQ<11>")
	)
	(segment
		(start 305.53406 -303.81448)
		(end 305.09083 -303.81448)
		(width 0.18288)
		(layer "In4.Cu")
		(net "M_B_CPU0_SA_DQ<11>")
	)
	(segment
		(start 308.574948 -301.6631)
		(end 308.574948 -302.131984)
		(width 0.18288)
		(layer "In4.Cu")
		(net "M_B_CPU0_SA_DQ<11>")
	)
	(segment
		(start 308.571646 -302.135286)
		(end 308.571646 -302.234854)
		(width 0.18288)
		(layer "In4.Cu")
		(net "M_B_CPU0_SA_DQ<11>")
	)
	(segment
		(start 310.854598 -301.52975)
		(end 310.67883 -301.705518)
		(width 0.18288)
		(layer "In4.Cu")
		(net "M_B_CPU0_SA_DQ<11>")
	)
	(segment
		(start 306.884832 -302.832516)
		(end 306.884832 -303.058576)
		(width 0.18288)
		(layer "In4.Cu")
		(net "M_B_CPU0_SA_DQ<11>")
	)
	(segment
		(start 309.265828 -302.131984)
		(end 309.265828 -301.68596)
		(width 0.18288)
		(layer "In4.Cu")
		(net "M_B_CPU0_SA_DQ<11>")
	)
	(segment
		(start 313.866276 -300.591474)
		(end 313.866022 -300.591728)
		(width 0.18288)
		(layer "In4.Cu")
		(net "M_B_CPU0_SA_DQ<11>")
	)
	(segment
		(start 302.911256 -304.955194)
		(end 301.82185 -304.955194)
		(width 0.18288)
		(layer "In4.Cu")
		(net "M_B_CPU0_SA_DQ<11>")
	)
	(segment
		(start 321.982084 -293.357808)
		(end 314.748418 -300.591474)
		(width 0.18288)
		(layer "In4.Cu")
		(net "M_B_CPU0_SA_DQ<11>")
	)
	(segment
		(start 309.082948 -301.50308)
		(end 308.734968 -301.50308)
		(width 0.18288)
		(layer "In4.Cu")
		(net "M_B_CPU0_SA_DQ<11>")
	)
	(segment
		(start 309.425848 -302.292004)
		(end 309.265828 -302.131984)
		(width 0.18288)
		(layer "In4.Cu")
		(net "M_B_CPU0_SA_DQ<11>")
	)
	(segment
		(start 305.09083 -303.81448)
		(end 304.86604 -304.03927)
		(width 0.18288)
		(layer "In4.Cu")
		(net "M_B_CPU0_SA_DQ<11>")
	)
	(segment
		(start 310.526684 -302.292004)
		(end 309.425848 -302.292004)
		(width 0.18288)
		(layer "In4.Cu")
		(net "M_B_CPU0_SA_DQ<11>")
	)
	(segment
		(start 301.50181 -304.346864)
		(end 301.15383 -304.346864)
		(width 0.18288)
		(layer "In4.Cu")
		(net "M_B_CPU0_SA_DQ<11>")
	)
	(segment
		(start 313.032648 -300.591728)
		(end 312.094626 -301.52975)
		(width 0.18288)
		(layer "In4.Cu")
		(net "M_B_CPU0_SA_DQ<11>")
	)
	(segment
		(start 301.66183 -304.795174)
		(end 301.66183 -304.506884)
		(width 0.18288)
		(layer "In4.Cu")
		(net "M_B_CPU0_SA_DQ<11>")
	)
	(segment
		(start 300.81093 -304.955194)
		(end 299.568362 -304.955194)
		(width 0.18288)
		(layer "In4.Cu")
		(net "M_B_CPU0_SA_DQ<11>")
	)
	(segment
		(start 306.76723 -304.03927)
		(end 305.75885 -304.03927)
		(width 0.18288)
		(layer "In4.Cu")
		(net "M_B_CPU0_SA_DQ<11>")
	)
	(segment
		(start 307.918104 -302.888396)
		(end 307.692044 -302.888396)
		(width 0.18288)
		(layer "In4.Cu")
		(net "M_B_CPU0_SA_DQ<11>")
	)
	(segment
		(start 331.83449 -278.718772)
		(end 325.367142 -285.18612)
		(width 0.18288)
		(layer "In4.Cu")
		(net "M_B_CPU0_SA_DQ<11>")
	)
	(segment
		(start 307.131212 -302.586136)
		(end 306.884832 -302.832516)
		(width 0.18288)
		(layer "In4.Cu")
		(net "M_B_CPU0_SA_DQ<11>")
	)
	(segment
		(start 309.265828 -301.68596)
		(end 309.082948 -301.50308)
		(width 0.18288)
		(layer "In4.Cu")
		(net "M_B_CPU0_SA_DQ<11>")
	)
	(segment
		(start 339.210904 -273.772376)
		(end 339.202014 -273.777456)
		(width 0.088646)
		(layer "In4.Cu")
		(net "M_B_CPU0_SA_DQ<11>")
	)
	(segment
		(start 334.041496 -276.214078)
		(end 334.032606 -276.219158)
		(width 0.088646)
		(layer "In4.Cu")
		(net "M_B_CPU0_SA_DQ<11>")
	)
	(segment
		(start 300.97095 -304.795174)
		(end 300.81093 -304.955194)
		(width 0.18288)
		(layer "In4.Cu")
		(net "M_B_CPU0_SA_DQ<11>")
	)
	(segment
		(start 301.15383 -304.346864)
		(end 300.97095 -304.529744)
		(width 0.18288)
		(layer "In4.Cu")
		(net "M_B_CPU0_SA_DQ<11>")
	)
	(segment
		(start 339.773006 -273.125438)
		(end 339.678772 -273.178778)
		(width 0.088646)
		(layer "In4.Cu")
		(net "M_B_CPU0_SA_DQ<11>")
	)
	(segment
		(start 310.67883 -302.139858)
		(end 310.526684 -302.292004)
		(width 0.18288)
		(layer "In4.Cu")
		(net "M_B_CPU0_SA_DQ<11>")
	)
	(segment
		(start 313.866022 -300.591728)
		(end 313.032648 -300.591728)
		(width 0.18288)
		(layer "In4.Cu")
		(net "M_B_CPU0_SA_DQ<11>")
	)
	(segment
		(start 307.389784 -302.586136)
		(end 307.131212 -302.586136)
		(width 0.18288)
		(layer "In4.Cu")
		(net "M_B_CPU0_SA_DQ<11>")
	)
	(segment
		(start 339.678772 -273.178778)
		(end 339.376258 -273.552158)
		(width 0.088646)
		(layer "In4.Cu")
		(net "M_B_CPU0_SA_DQ<11>")
	)
	(segment
		(start 307.203348 -303.603152)
		(end 306.76723 -304.03927)
		(width 0.18288)
		(layer "In4.Cu")
		(net "M_B_CPU0_SA_DQ<11>")
	)
	(segment
		(start 308.734968 -301.50308)
		(end 308.574948 -301.6631)
		(width 0.18288)
		(layer "In4.Cu")
		(net "M_B_CPU0_SA_DQ<11>")
	)
	(segment
		(start 334.98155 -274.586192)
		(end 334.97266 -274.591272)
		(width 0.088646)
		(layer "In4.Cu")
		(net "M_B_CPU0_SA_DQ<11>")
	)
	(segment
		(start 307.203348 -303.377092)
		(end 307.203348 -303.603152)
		(width 0.18288)
		(layer "In4.Cu")
		(net "M_B_CPU0_SA_DQ<11>")
	)
	(segment
		(start 334.97266 -274.591272)
		(end 334.966564 -274.594828)
		(width 0.088646)
		(layer "In4.Cu")
		(net "M_B_CPU0_SA_DQ<11>")
	)
	(segment
		(start 299.568362 -304.955194)
		(end 299.029882 -304.416714)
		(width 0.18288)
		(layer "In4.Cu")
		(net "M_B_CPU0_SA_DQ<11>")
	)
	(segment
		(start 303.82718 -304.03927)
		(end 302.911256 -304.955194)
		(width 0.18288)
		(layer "In4.Cu")
		(net "M_B_CPU0_SA_DQ<11>")
	)
	(segment
		(start 338.272374 -273.77136)
		(end 338.26196 -273.777456)
		(width 0.088646)
		(layer "In4.Cu")
		(net "M_B_CPU0_SA_DQ<11>")
	)
	(segment
		(start 334.511396 -275.400008)
		(end 334.502506 -275.405088)
		(width 0.088646)
		(layer "In4.Cu")
		(net "M_B_CPU0_SA_DQ<11>")
	)
	(segment
		(start 300.97095 -304.529744)
		(end 300.97095 -304.795174)
		(width 0.18288)
		(layer "In4.Cu")
		(net "M_B_CPU0_SA_DQ<11>")
	)
	(segment
		(start 305.75885 -304.03927)
		(end 305.53406 -303.81448)
		(width 0.18288)
		(layer "In4.Cu")
		(net "M_B_CPU0_SA_DQ<11>")
	)
	(segment
		(start 312.094626 -301.52975)
		(end 310.854598 -301.52975)
		(width 0.18288)
		(layer "In4.Cu")
		(net "M_B_CPU0_SA_DQ<11>")
	)
	(segment
		(start 333.43342 -277.119842)
		(end 331.83449 -278.718772)
		(width 0.088646)
		(layer "In4.Cu")
		(net "M_B_CPU0_SA_DQ<11>")
	)
	(segment
		(start 306.884832 -303.058576)
		(end 307.203348 -303.377092)
		(width 0.18288)
		(layer "In4.Cu")
		(net "M_B_CPU0_SA_DQ<11>")
	)
	(segment
		(start 308.574948 -302.131984)
		(end 308.571646 -302.135286)
		(width 0.18288)
		(layer "In4.Cu")
		(net "M_B_CPU0_SA_DQ<11>")
	)
	(segment
		(start 301.82185 -304.955194)
		(end 301.66183 -304.795174)
		(width 0.18288)
		(layer "In4.Cu")
		(net "M_B_CPU0_SA_DQ<11>")
	)
	(segment
		(start 335.160112 -274.257008)
		(end 335.160112 -274.266914)
		(width 0.088646)
		(layer "In4.Cu")
		(net "M_B_CPU0_SA_DQ<11>")
	)
	(segment
		(start 314.748418 -300.591474)
		(end 313.866276 -300.591474)
		(width 0.18288)
		(layer "In4.Cu")
		(net "M_B_CPU0_SA_DQ<11>")
	)
	(segment
		(start 340.712806 -273.125438)
		(end 340.701122 -273.132042)
		(width 0.088646)
		(layer "In4.Cu")
		(net "M_B_CPU0_SA_DQ<11>")
	)
	(segment
		(start 310.67883 -301.705518)
		(end 310.67883 -302.139858)
		(width 0.18288)
		(layer "In4.Cu")
		(net "M_B_CPU0_SA_DQ<11>")
	)
	(segment
		(start 334.220058 -275.876258)
		(end 334.220058 -275.8948)
		(width 0.088646)
		(layer "In4.Cu")
		(net "M_B_CPU0_SA_DQ<11>")
	)
	(arc
		(start 333.750412 -276.708616)
		(mid 333.702733 -276.891516)
		(end 333.57185 -277.027894)
		(width 0.088646)
		(layer "In4.Cu")
		(net "M_B_CPU0_SA_DQ<11>")
	)
	(arc
		(start 335.44256 -273.777456)
		(mid 335.238225 -273.980061)
		(end 335.160112 -274.257008)
		(width 0.088646)
		(layer "In4.Cu")
		(net "M_B_CPU0_SA_DQ<11>")
	)
	(arc
		(start 334.502506 -275.405088)
		(mid 334.30022 -275.604069)
		(end 334.220058 -275.876258)
		(width 0.088646)
		(layer "In4.Cu")
		(net "M_B_CPU0_SA_DQ<11>")
	)
	(arc
		(start 341.081614 -273.12874)
		(mid 340.89766 -273.078611)
		(end 340.712806 -273.125438)
		(width 0.088646)
		(layer "In4.Cu")
		(net "M_B_CPU0_SA_DQ<11>")
	)
	(arc
		(start 334.689958 -275.08073)
		(mid 334.642279 -275.26363)
		(end 334.511396 -275.400008)
		(width 0.088646)
		(layer "In4.Cu")
		(net "M_B_CPU0_SA_DQ<11>")
	)
	(arc
		(start 340.141814 -273.12874)
		(mid 339.95786 -273.078611)
		(end 339.773006 -273.125438)
		(width 0.088646)
		(layer "In4.Cu")
		(net "M_B_CPU0_SA_DQ<11>")
	)
	(arc
		(start 338.827618 -273.777456)
		(mid 338.550805 -273.701586)
		(end 338.272374 -273.77136)
		(width 0.088646)
		(layer "In4.Cu")
		(net "M_B_CPU0_SA_DQ<11>")
	)
	(arc
		(start 338.26196 -273.777456)
		(mid 338.074762 -273.827599)
		(end 337.887564 -273.777456)
		(width 0.088646)
		(layer "In4.Cu")
		(net "M_B_CPU0_SA_DQ<11>")
	)
	(arc
		(start 334.220058 -275.8948)
		(mid 334.172379 -276.0777)
		(end 334.041496 -276.214078)
		(width 0.088646)
		(layer "In4.Cu")
		(net "M_B_CPU0_SA_DQ<11>")
	)
	(arc
		(start 335.160112 -274.266914)
		(mid 335.112433 -274.449814)
		(end 334.98155 -274.586192)
		(width 0.088646)
		(layer "In4.Cu")
		(net "M_B_CPU0_SA_DQ<11>")
	)
	(arc
		(start 340.701122 -273.132042)
		(mid 340.421017 -273.204484)
		(end 340.141814 -273.12874)
		(width 0.088646)
		(layer "In4.Cu")
		(net "M_B_CPU0_SA_DQ<11>")
	)
	(arc
		(start 334.966564 -274.594828)
		(mid 334.763977 -274.801179)
		(end 334.689958 -275.08073)
		(width 0.088646)
		(layer "In4.Cu")
		(net "M_B_CPU0_SA_DQ<11>")
	)
	(arc
		(start 333.56296 -277.032974)
		(mid 333.550139 -277.040083)
		(end 333.537052 -277.04669)
		(width 0.088646)
		(layer "In4.Cu")
		(net "M_B_CPU0_SA_DQ<11>")
	)
	(arc
		(start 333.537052 -277.04669)
		(mid 333.482119 -277.078849)
		(end 333.43342 -277.119842)
		(width 0.088646)
		(layer "In4.Cu")
		(net "M_B_CPU0_SA_DQ<11>")
	)
	(arc
		(start 334.032606 -276.219158)
		(mid 333.829783 -276.419389)
		(end 333.750412 -276.693122)
		(width 0.088646)
		(layer "In4.Cu")
		(net "M_B_CPU0_SA_DQ<11>")
	)
	(arc
		(start 336.947764 -273.777456)
		(mid 336.665062 -273.70168)
		(end 336.38236 -273.777456)
		(width 0.088646)
		(layer "In4.Cu")
		(net "M_B_CPU0_SA_DQ<11>")
	)
	(arc
		(start 337.32216 -273.777456)
		(mid 337.134962 -273.827599)
		(end 336.947764 -273.777456)
		(width 0.088646)
		(layer "In4.Cu")
		(net "M_B_CPU0_SA_DQ<11>")
	)
	(arc
		(start 337.887564 -273.777456)
		(mid 337.604862 -273.70168)
		(end 337.32216 -273.777456)
		(width 0.088646)
		(layer "In4.Cu")
		(net "M_B_CPU0_SA_DQ<11>")
	)
	(arc
		(start 341.834216 -273.453098)
		(mid 341.650147 -273.428874)
		(end 341.478616 -273.357848)
		(width 0.088646)
		(layer "In4.Cu")
		(net "M_B_CPU0_SA_DQ<11>")
	)
	(arc
		(start 336.38236 -273.777456)
		(mid 336.195162 -273.827599)
		(end 336.007964 -273.777456)
		(width 0.088646)
		(layer "In4.Cu")
		(net "M_B_CPU0_SA_DQ<11>")
	)
	(arc
		(start 336.007964 -273.777456)
		(mid 335.725262 -273.70168)
		(end 335.44256 -273.777456)
		(width 0.088646)
		(layer "In4.Cu")
		(net "M_B_CPU0_SA_DQ<11>")
	)
	(arc
		(start 339.202014 -273.777456)
		(mid 339.014816 -273.827599)
		(end 338.827618 -273.777456)
		(width 0.088646)
		(layer "In4.Cu")
		(net "M_B_CPU0_SA_DQ<11>")
	)
	(arc
		(start 339.376258 -273.552158)
		(mid 339.314573 -273.67804)
		(end 339.210904 -273.772376)
		(width 0.088646)
		(layer "In4.Cu")
		(net "M_B_CPU0_SA_DQ<11>")
	)
	(segment
		(start 299.029882 -306.116736)
		(end 297.899582 -306.116736)
		(width 0.20066)
		(layer "F.Cu")
		(net "M_B_CPU0_SA_DQ<10>")
	)
	(segment
		(start 295.777158 -306.161186)
		(end 295.777158 -305.835558)
		(width 0.20066)
		(layer "F.Cu")
		(net "M_B_CPU0_SA_DQ<10>")
	)
	(segment
		(start 292.67531 -305.681634)
		(end 291.937948 -305.681634)
		(width 0.20066)
		(layer "F.Cu")
		(net "M_B_CPU0_SA_DQ<10>")
	)
	(segment
		(start 296.373042 -306.328572)
		(end 295.944544 -306.328572)
		(width 0.20066)
		(layer "F.Cu")
		(net "M_B_CPU0_SA_DQ<10>")
	)
	(segment
		(start 295.000426 -305.691794)
		(end 292.940486 -305.691794)
		(width 0.1016)
		(layer "F.Cu")
		(net "M_B_CPU0_SA_DQ<10>")
	)
	(segment
		(start 291.937948 -305.681634)
		(end 291.502846 -306.116736)
		(width 0.20066)
		(layer "F.Cu")
		(net "M_B_CPU0_SA_DQ<10>")
	)
	(segment
		(start 291.502846 -306.116736)
		(end 290.355782 -306.116736)
		(width 0.20066)
		(layer "F.Cu")
		(net "M_B_CPU0_SA_DQ<10>")
	)
	(segment
		(start 295.633394 -305.691794)
		(end 295.000426 -305.691794)
		(width 0.20066)
		(layer "F.Cu")
		(net "M_B_CPU0_SA_DQ<10>")
	)
	(segment
		(start 292.940486 -305.691794)
		(end 292.68547 -305.691794)
		(width 0.101854)
		(layer "F.Cu")
		(net "M_B_CPU0_SA_DQ<10>")
	)
	(segment
		(start 295.944544 -306.328572)
		(end 295.777158 -306.161186)
		(width 0.20066)
		(layer "F.Cu")
		(net "M_B_CPU0_SA_DQ<10>")
	)
	(segment
		(start 297.899582 -306.116736)
		(end 296.584878 -306.116736)
		(width 0.20066)
		(layer "F.Cu")
		(net "M_B_CPU0_SA_DQ<10>")
	)
	(segment
		(start 341.364316 -273.730974)
		(end 341.364316 -274.26666)
		(width 0.20066)
		(layer "F.Cu")
		(net "M_B_CPU0_SA_DQ<10>")
	)
	(segment
		(start 292.68547 -305.691794)
		(end 292.67531 -305.681634)
		(width 0.101854)
		(layer "F.Cu")
		(net "M_B_CPU0_SA_DQ<10>")
	)
	(segment
		(start 296.584878 -306.116736)
		(end 296.373042 -306.328572)
		(width 0.20066)
		(layer "F.Cu")
		(net "M_B_CPU0_SA_DQ<10>")
	)
	(segment
		(start 341.364316 -274.26666)
		(end 341.364062 -274.266914)
		(width 0.20066)
		(layer "F.Cu")
		(net "M_B_CPU0_SA_DQ<10>")
	)
	(segment
		(start 295.777158 -305.835558)
		(end 295.633394 -305.691794)
		(width 0.20066)
		(layer "F.Cu")
		(net "M_B_CPU0_SA_DQ<10>")
	)
	(segment
		(start 305.240436 -305.155092)
		(end 305.080416 -305.315112)
		(width 0.18288)
		(layer "In4.Cu")
		(net "M_B_CPU0_SA_DQ<10>")
	)
	(segment
		(start 322.713096 -294.210994)
		(end 314.750704 -302.173386)
		(width 0.18288)
		(layer "In4.Cu")
		(net "M_B_CPU0_SA_DQ<10>")
	)
	(segment
		(start 305.931316 -305.846226)
		(end 305.771296 -305.686206)
		(width 0.18288)
		(layer "In4.Cu")
		(net "M_B_CPU0_SA_DQ<10>")
	)
	(segment
		(start 340.706964 -273.777456)
		(end 340.701122 -273.774154)
		(width 0.088646)
		(layer "In4.Cu")
		(net "M_B_CPU0_SA_DQ<10>")
	)
	(segment
		(start 301.18431 -306.19954)
		(end 301.02429 -306.35956)
		(width 0.18288)
		(layer "In4.Cu")
		(net "M_B_CPU0_SA_DQ<10>")
	)
	(segment
		(start 334.51165 -277.027894)
		(end 334.50276 -277.032974)
		(width 0.088646)
		(layer "In4.Cu")
		(net "M_B_CPU0_SA_DQ<10>")
	)
	(segment
		(start 305.080416 -305.315112)
		(end 305.080416 -305.686206)
		(width 0.18288)
		(layer "In4.Cu")
		(net "M_B_CPU0_SA_DQ<10>")
	)
	(segment
		(start 300.1518 -306.761896)
		(end 299.50664 -306.116736)
		(width 0.18288)
		(layer "In4.Cu")
		(net "M_B_CPU0_SA_DQ<10>")
	)
	(segment
		(start 340.811104 -273.83867)
		(end 340.80958 -273.837908)
		(width 0.088646)
		(layer "In4.Cu")
		(net "M_B_CPU0_SA_DQ<10>")
	)
	(segment
		(start 332.557374 -279.441402)
		(end 326.195436 -285.80334)
		(width 0.18288)
		(layer "In4.Cu")
		(net "M_B_CPU0_SA_DQ<10>")
	)
	(segment
		(start 301.71517 -306.597558)
		(end 301.71517 -306.38242)
		(width 0.18288)
		(layer "In4.Cu")
		(net "M_B_CPU0_SA_DQ<10>")
	)
	(segment
		(start 312.096912 -302.7299)
		(end 311.936892 -302.56988)
		(width 0.18288)
		(layer "In4.Cu")
		(net "M_B_CPU0_SA_DQ<10>")
	)
	(segment
		(start 335.91246 -274.591272)
		(end 335.900268 -274.598384)
		(width 0.088646)
		(layer "In4.Cu")
		(net "M_B_CPU0_SA_DQ<10>")
	)
	(segment
		(start 301.88789 -306.770278)
		(end 301.71517 -306.597558)
		(width 0.18288)
		(layer "In4.Cu")
		(net "M_B_CPU0_SA_DQ<10>")
	)
	(segment
		(start 301.53229 -306.19954)
		(end 301.18431 -306.19954)
		(width 0.18288)
		(layer "In4.Cu")
		(net "M_B_CPU0_SA_DQ<10>")
	)
	(segment
		(start 332.722728 -279.276048)
		(end 332.557374 -279.441402)
		(width 0.088646)
		(layer "In4.Cu")
		(net "M_B_CPU0_SA_DQ<10>")
	)
	(segment
		(start 306.644294 -305.846226)
		(end 305.931316 -305.846226)
		(width 0.18288)
		(layer "In4.Cu")
		(net "M_B_CPU0_SA_DQ<10>")
	)
	(segment
		(start 310.481218 -304.84191)
		(end 307.64861 -304.84191)
		(width 0.18288)
		(layer "In4.Cu")
		(net "M_B_CPU0_SA_DQ<10>")
	)
	(segment
		(start 333.845408 -277.897844)
		(end 333.399384 -277.897844)
		(width 0.088646)
		(layer "In4.Cu")
		(net "M_B_CPU0_SA_DQ<10>")
	)
	(segment
		(start 301.02429 -306.601876)
		(end 300.86427 -306.761896)
		(width 0.18288)
		(layer "In4.Cu")
		(net "M_B_CPU0_SA_DQ<10>")
	)
	(segment
		(start 334.220058 -277.508462)
		(end 334.220058 -277.522686)
		(width 0.088646)
		(layer "In4.Cu")
		(net "M_B_CPU0_SA_DQ<10>")
	)
	(segment
		(start 311.153048 -304.17008)
		(end 310.481218 -304.84191)
		(width 0.18288)
		(layer "In4.Cu")
		(net "M_B_CPU0_SA_DQ<10>")
	)
	(segment
		(start 312.27014 -303.14138)
		(end 312.096912 -302.968152)
		(width 0.18288)
		(layer "In4.Cu")
		(net "M_B_CPU0_SA_DQ<10>")
	)
	(segment
		(start 339.861144 -274.191222)
		(end 339.859112 -274.27555)
		(width 0.088646)
		(layer "In4.Cu")
		(net "M_B_CPU0_SA_DQ<10>")
	)
	(segment
		(start 334.690212 -276.693122)
		(end 334.690212 -276.708616)
		(width 0.088646)
		(layer "In4.Cu")
		(net "M_B_CPU0_SA_DQ<10>")
	)
	(segment
		(start 335.451196 -275.400008)
		(end 335.442306 -275.405088)
		(width 0.088646)
		(layer "In4.Cu")
		(net "M_B_CPU0_SA_DQ<10>")
	)
	(segment
		(start 305.771296 -305.686206)
		(end 305.771296 -305.337972)
		(width 0.18288)
		(layer "In4.Cu")
		(net "M_B_CPU0_SA_DQ<10>")
	)
	(segment
		(start 302.741838 -306.770278)
		(end 301.88789 -306.770278)
		(width 0.18288)
		(layer "In4.Cu")
		(net "M_B_CPU0_SA_DQ<10>")
	)
	(segment
		(start 312.096912 -302.968152)
		(end 312.096912 -302.7299)
		(width 0.18288)
		(layer "In4.Cu")
		(net "M_B_CPU0_SA_DQ<10>")
	)
	(segment
		(start 311.153048 -303.10328)
		(end 311.153048 -304.17008)
		(width 0.18288)
		(layer "In4.Cu")
		(net "M_B_CPU0_SA_DQ<10>")
	)
	(segment
		(start 311.936892 -302.56988)
		(end 311.686448 -302.56988)
		(width 0.18288)
		(layer "In4.Cu")
		(net "M_B_CPU0_SA_DQ<10>")
	)
	(segment
		(start 301.71517 -306.38242)
		(end 301.53229 -306.19954)
		(width 0.18288)
		(layer "In4.Cu")
		(net "M_B_CPU0_SA_DQ<10>")
	)
	(segment
		(start 326.195436 -285.80334)
		(end 322.713096 -294.210994)
		(width 0.18288)
		(layer "In4.Cu")
		(net "M_B_CPU0_SA_DQ<10>")
	)
	(segment
		(start 314.481972 -303.14138)
		(end 312.27014 -303.14138)
		(width 0.18288)
		(layer "In4.Cu")
		(net "M_B_CPU0_SA_DQ<10>")
	)
	(segment
		(start 305.588416 -305.155092)
		(end 305.240436 -305.155092)
		(width 0.18288)
		(layer "In4.Cu")
		(net "M_B_CPU0_SA_DQ<10>")
	)
	(segment
		(start 335.159858 -275.876258)
		(end 335.159858 -275.8948)
		(width 0.088646)
		(layer "In4.Cu")
		(net "M_B_CPU0_SA_DQ<10>")
	)
	(segment
		(start 305.080416 -305.686206)
		(end 304.920396 -305.846226)
		(width 0.18288)
		(layer "In4.Cu")
		(net "M_B_CPU0_SA_DQ<10>")
	)
	(segment
		(start 332.722728 -278.5745)
		(end 332.722728 -279.276048)
		(width 0.088646)
		(layer "In4.Cu")
		(net "M_B_CPU0_SA_DQ<10>")
	)
	(segment
		(start 314.750704 -302.173386)
		(end 314.750704 -302.872648)
		(width 0.18288)
		(layer "In4.Cu")
		(net "M_B_CPU0_SA_DQ<10>")
	)
	(segment
		(start 299.50664 -306.116736)
		(end 299.029882 -306.116736)
		(width 0.18288)
		(layer "In4.Cu")
		(net "M_B_CPU0_SA_DQ<10>")
	)
	(segment
		(start 314.750704 -302.872648)
		(end 314.481972 -303.14138)
		(width 0.18288)
		(layer "In4.Cu")
		(net "M_B_CPU0_SA_DQ<10>")
	)
	(segment
		(start 333.399384 -277.897844)
		(end 332.722728 -278.5745)
		(width 0.088646)
		(layer "In4.Cu")
		(net "M_B_CPU0_SA_DQ<10>")
	)
	(segment
		(start 307.64861 -304.84191)
		(end 306.644294 -305.846226)
		(width 0.18288)
		(layer "In4.Cu")
		(net "M_B_CPU0_SA_DQ<10>")
	)
	(segment
		(start 305.771296 -305.337972)
		(end 305.588416 -305.155092)
		(width 0.18288)
		(layer "In4.Cu")
		(net "M_B_CPU0_SA_DQ<10>")
	)
	(segment
		(start 334.981296 -276.214078)
		(end 334.972406 -276.219158)
		(width 0.088646)
		(layer "In4.Cu")
		(net "M_B_CPU0_SA_DQ<10>")
	)
	(segment
		(start 303.66589 -305.846226)
		(end 302.741838 -306.770278)
		(width 0.18288)
		(layer "In4.Cu")
		(net "M_B_CPU0_SA_DQ<10>")
	)
	(segment
		(start 339.297518 -274.591272)
		(end 339.287104 -274.585176)
		(width 0.088646)
		(layer "In4.Cu")
		(net "M_B_CPU0_SA_DQ<10>")
	)
	(segment
		(start 301.02429 -306.35956)
		(end 301.02429 -306.601876)
		(width 0.18288)
		(layer "In4.Cu")
		(net "M_B_CPU0_SA_DQ<10>")
	)
	(segment
		(start 304.920396 -305.846226)
		(end 303.66589 -305.846226)
		(width 0.18288)
		(layer "In4.Cu")
		(net "M_B_CPU0_SA_DQ<10>")
	)
	(segment
		(start 300.86427 -306.761896)
		(end 300.1518 -306.761896)
		(width 0.18288)
		(layer "In4.Cu")
		(net "M_B_CPU0_SA_DQ<10>")
	)
	(segment
		(start 340.80704 -273.836384)
		(end 340.706964 -273.777456)
		(width 0.088646)
		(layer "In4.Cu")
		(net "M_B_CPU0_SA_DQ<10>")
	)
	(segment
		(start 311.686448 -302.56988)
		(end 311.153048 -303.10328)
		(width 0.18288)
		(layer "In4.Cu")
		(net "M_B_CPU0_SA_DQ<10>")
	)
	(arc
		(start 341.364062 -274.266914)
		(mid 341.101149 -274.035276)
		(end 340.811104 -273.83867)
		(width 0.088646)
		(layer "In4.Cu")
		(net "M_B_CPU0_SA_DQ<10>")
	)
	(arc
		(start 334.690212 -276.708616)
		(mid 334.642533 -276.891516)
		(end 334.51165 -277.027894)
		(width 0.088646)
		(layer "In4.Cu")
		(net "M_B_CPU0_SA_DQ<10>")
	)
	(arc
		(start 339.864954 -274.187412)
		(mid 339.86226 -274.188528)
		(end 339.861144 -274.191222)
		(width 0.088646)
		(layer "In4.Cu")
		(net "M_B_CPU0_SA_DQ<10>")
	)
	(arc
		(start 335.159858 -275.8948)
		(mid 335.112179 -276.0777)
		(end 334.981296 -276.214078)
		(width 0.088646)
		(layer "In4.Cu")
		(net "M_B_CPU0_SA_DQ<10>")
	)
	(arc
		(start 339.287104 -274.585176)
		(mid 339.008672 -274.51533)
		(end 338.73186 -274.591272)
		(width 0.088646)
		(layer "In4.Cu")
		(net "M_B_CPU0_SA_DQ<10>")
	)
	(arc
		(start 339.671914 -274.591272)
		(mid 339.484716 -274.641415)
		(end 339.297518 -274.591272)
		(width 0.088646)
		(layer "In4.Cu")
		(net "M_B_CPU0_SA_DQ<10>")
	)
	(arc
		(start 336.477864 -274.591272)
		(mid 336.195162 -274.515496)
		(end 335.91246 -274.591272)
		(width 0.088646)
		(layer "In4.Cu")
		(net "M_B_CPU0_SA_DQ<10>")
	)
	(arc
		(start 334.220058 -277.522686)
		(mid 334.172379 -277.705586)
		(end 334.041496 -277.841964)
		(width 0.088646)
		(layer "In4.Cu")
		(net "M_B_CPU0_SA_DQ<10>")
	)
	(arc
		(start 337.79206 -274.591272)
		(mid 337.604862 -274.641415)
		(end 337.417664 -274.591272)
		(width 0.088646)
		(layer "In4.Cu")
		(net "M_B_CPU0_SA_DQ<10>")
	)
	(arc
		(start 334.50276 -277.032974)
		(mid 334.299279 -277.233778)
		(end 334.220058 -277.508462)
		(width 0.088646)
		(layer "In4.Cu")
		(net "M_B_CPU0_SA_DQ<10>")
	)
	(arc
		(start 338.73186 -274.591272)
		(mid 338.544662 -274.641415)
		(end 338.357464 -274.591272)
		(width 0.088646)
		(layer "In4.Cu")
		(net "M_B_CPU0_SA_DQ<10>")
	)
	(arc
		(start 340.701122 -273.774154)
		(mid 340.420987 -273.701838)
		(end 340.141814 -273.77771)
		(width 0.088646)
		(layer "In4.Cu")
		(net "M_B_CPU0_SA_DQ<10>")
	)
	(arc
		(start 338.357464 -274.591272)
		(mid 338.074762 -274.515496)
		(end 337.79206 -274.591272)
		(width 0.088646)
		(layer "In4.Cu")
		(net "M_B_CPU0_SA_DQ<10>")
	)
	(arc
		(start 334.041496 -277.841964)
		(mid 333.947321 -277.883473)
		(end 333.845408 -277.897844)
		(width 0.088646)
		(layer "In4.Cu")
		(net "M_B_CPU0_SA_DQ<10>")
	)
	(arc
		(start 337.417664 -274.591272)
		(mid 337.134962 -274.515496)
		(end 336.85226 -274.591272)
		(width 0.088646)
		(layer "In4.Cu")
		(net "M_B_CPU0_SA_DQ<10>")
	)
	(arc
		(start 336.85226 -274.591272)
		(mid 336.665062 -274.641415)
		(end 336.477864 -274.591272)
		(width 0.088646)
		(layer "In4.Cu")
		(net "M_B_CPU0_SA_DQ<10>")
	)
	(arc
		(start 335.900268 -274.598384)
		(mid 335.70204 -274.804232)
		(end 335.629758 -275.08073)
		(width 0.088646)
		(layer "In4.Cu")
		(net "M_B_CPU0_SA_DQ<10>")
	)
	(arc
		(start 335.629758 -275.08073)
		(mid 335.582079 -275.26363)
		(end 335.451196 -275.400008)
		(width 0.088646)
		(layer "In4.Cu")
		(net "M_B_CPU0_SA_DQ<10>")
	)
	(arc
		(start 340.80958 -273.837908)
		(mid 340.808304 -273.837157)
		(end 340.80704 -273.836384)
		(width 0.088646)
		(layer "In4.Cu")
		(net "M_B_CPU0_SA_DQ<10>")
	)
	(arc
		(start 335.442306 -275.405088)
		(mid 335.24002 -275.604069)
		(end 335.159858 -275.876258)
		(width 0.088646)
		(layer "In4.Cu")
		(net "M_B_CPU0_SA_DQ<10>")
	)
	(arc
		(start 339.859112 -274.27555)
		(mid 339.806842 -274.457915)
		(end 339.671914 -274.591272)
		(width 0.088646)
		(layer "In4.Cu")
		(net "M_B_CPU0_SA_DQ<10>")
	)
	(arc
		(start 334.972406 -276.219158)
		(mid 334.769583 -276.419389)
		(end 334.690212 -276.693122)
		(width 0.088646)
		(layer "In4.Cu")
		(net "M_B_CPU0_SA_DQ<10>")
	)
	(arc
		(start 340.141814 -273.77771)
		(mid 339.956197 -273.950676)
		(end 339.864954 -274.187412)
		(width 0.088646)
		(layer "In4.Cu")
		(net "M_B_CPU0_SA_DQ<10>")
	)
	(segment
		(start 292.236398 -316.316614)
		(end 291.811456 -315.891672)
		(width 0.20066)
		(layer "F.Cu")
		(net "M_B_CPU0_SA_DQ<0>")
	)
	(segment
		(start 288.28746 -316.555374)
		(end 287.828736 -316.555374)
		(width 0.20066)
		(layer "F.Cu")
		(net "M_B_CPU0_SA_DQ<0>")
	)
	(segment
		(start 288.46018 -316.093094)
		(end 288.46018 -316.382654)
		(width 0.20066)
		(layer "F.Cu")
		(net "M_B_CPU0_SA_DQ<0>")
	)
	(segment
		(start 294.904414 -316.316614)
		(end 293.799514 -316.316614)
		(width 0.20066)
		(layer "F.Cu")
		(net "M_B_CPU0_SA_DQ<0>")
	)
	(segment
		(start 293.799514 -316.316614)
		(end 292.236398 -316.316614)
		(width 0.20066)
		(layer "F.Cu")
		(net "M_B_CPU0_SA_DQ<0>")
	)
	(segment
		(start 289.48761 -315.891672)
		(end 289.239706 -315.891672)
		(width 0.101854)
		(layer "F.Cu")
		(net "M_B_CPU0_SA_DQ<0>")
	)
	(segment
		(start 287.828736 -316.555374)
		(end 287.589976 -316.316614)
		(width 0.20066)
		(layer "F.Cu")
		(net "M_B_CPU0_SA_DQ<0>")
	)
	(segment
		(start 288.66973 -315.883544)
		(end 288.46018 -316.093094)
		(width 0.20066)
		(layer "F.Cu")
		(net "M_B_CPU0_SA_DQ<0>")
	)
	(segment
		(start 291.556694 -315.891672)
		(end 289.48761 -315.891672)
		(width 0.1016)
		(layer "F.Cu")
		(net "M_B_CPU0_SA_DQ<0>")
	)
	(segment
		(start 291.811456 -315.891672)
		(end 291.556694 -315.891672)
		(width 0.20066)
		(layer "F.Cu")
		(net "M_B_CPU0_SA_DQ<0>")
	)
	(segment
		(start 288.46018 -316.382654)
		(end 288.28746 -316.555374)
		(width 0.20066)
		(layer "F.Cu")
		(net "M_B_CPU0_SA_DQ<0>")
	)
	(segment
		(start 289.231578 -315.883544)
		(end 288.66973 -315.883544)
		(width 0.20066)
		(layer "F.Cu")
		(net "M_B_CPU0_SA_DQ<0>")
	)
	(segment
		(start 337.134962 -276.172676)
		(end 337.134962 -276.708616)
		(width 0.20066)
		(layer "F.Cu")
		(net "M_B_CPU0_SA_DQ<0>")
	)
	(segment
		(start 287.589976 -316.316614)
		(end 286.255714 -316.316614)
		(width 0.20066)
		(layer "F.Cu")
		(net "M_B_CPU0_SA_DQ<0>")
	)
	(segment
		(start 289.239706 -315.891672)
		(end 289.231578 -315.883544)
		(width 0.101854)
		(layer "F.Cu")
		(net "M_B_CPU0_SA_DQ<0>")
	)
	(segment
		(start 300.540674 -316.739016)
		(end 300.075092 -316.273434)
		(width 0.18288)
		(layer "In2.Cu")
		(net "M_B_CPU0_SA_DQ<0>")
	)
	(segment
		(start 337.152488 -276.708616)
		(end 337.153758 -276.709886)
		(width 0.088646)
		(layer "In2.Cu")
		(net "M_B_CPU0_SA_DQ<0>")
	)
	(segment
		(start 296.780966 -315.06287)
		(end 294.904414 -316.316614)
		(width 0.18288)
		(layer "In2.Cu")
		(net "M_B_CPU0_SA_DQ<0>")
	)
	(segment
		(start 332.506066 -285.477966)
		(end 332.317598 -285.932372)
		(width 0.18288)
		(layer "In2.Cu")
		(net "M_B_CPU0_SA_DQ<0>")
	)
	(segment
		(start 322.873116 -306.8447)
		(end 315.074046 -314.64377)
		(width 0.18288)
		(layer "In2.Cu")
		(net "M_B_CPU0_SA_DQ<0>")
	)
	(segment
		(start 311.02681 -316.513972)
		(end 309.89905 -316.513972)
		(width 0.18288)
		(layer "In2.Cu")
		(net "M_B_CPU0_SA_DQ<0>")
	)
	(segment
		(start 304.710592 -316.641226)
		(end 304.464466 -316.887352)
		(width 0.18288)
		(layer "In2.Cu")
		(net "M_B_CPU0_SA_DQ<0>")
	)
	(segment
		(start 337.039712 -279.140412)
		(end 337.039712 -279.150318)
		(width 0.088646)
		(layer "In2.Cu")
		(net "M_B_CPU0_SA_DQ<0>")
	)
	(segment
		(start 307.01869 -316.74181)
		(end 306.277518 -316.74181)
		(width 0.18288)
		(layer "In2.Cu")
		(net "M_B_CPU0_SA_DQ<0>")
	)
	(segment
		(start 315.074046 -314.64377)
		(end 315.074046 -314.956698)
		(width 0.18288)
		(layer "In2.Cu")
		(net "M_B_CPU0_SA_DQ<0>")
	)
	(segment
		(start 324.863206 -300.376844)
		(end 324.226428 -303.578006)
		(width 0.18288)
		(layer "In2.Cu")
		(net "M_B_CPU0_SA_DQ<0>")
	)
	(segment
		(start 329.40117 -289.42919)
		(end 324.863206 -300.376844)
		(width 0.18288)
		(layer "In2.Cu")
		(net "M_B_CPU0_SA_DQ<0>")
	)
	(segment
		(start 337.80095 -277.84171)
		(end 337.79206 -277.84679)
		(width 0.088646)
		(layer "In2.Cu")
		(net "M_B_CPU0_SA_DQ<0>")
	)
	(segment
		(start 309.89905 -316.513972)
		(end 309.674006 -316.739016)
		(width 0.18288)
		(layer "In2.Cu")
		(net "M_B_CPU0_SA_DQ<0>")
	)
	(segment
		(start 307.56479 -316.739016)
		(end 307.405532 -316.898274)
		(width 0.18288)
		(layer "In2.Cu")
		(net "M_B_CPU0_SA_DQ<0>")
	)
	(segment
		(start 337.79206 -277.198074)
		(end 337.80095 -277.203154)
		(width 0.088646)
		(layer "In2.Cu")
		(net "M_B_CPU0_SA_DQ<0>")
	)
	(segment
		(start 336.86115 -279.469596)
		(end 336.85226 -279.474676)
		(width 0.088646)
		(layer "In2.Cu")
		(net "M_B_CPU0_SA_DQ<0>")
	)
	(segment
		(start 337.33105 -278.65578)
		(end 337.32216 -278.66086)
		(width 0.088646)
		(layer "In2.Cu")
		(net "M_B_CPU0_SA_DQ<0>")
	)
	(segment
		(start 299.209968 -315.041788)
		(end 298.258992 -315.041788)
		(width 0.18288)
		(layer "In2.Cu")
		(net "M_B_CPU0_SA_DQ<0>")
	)
	(segment
		(start 324.226428 -303.578006)
		(end 322.873116 -306.8447)
		(width 0.18288)
		(layer "In2.Cu")
		(net "M_B_CPU0_SA_DQ<0>")
	)
	(segment
		(start 333.22133 -281.840686)
		(end 333.006446 -282.05557)
		(width 0.088646)
		(layer "In2.Cu")
		(net "M_B_CPU0_SA_DQ<0>")
	)
	(segment
		(start 331.90434 -286.929068)
		(end 329.40117 -289.42919)
		(width 0.18288)
		(layer "In2.Cu")
		(net "M_B_CPU0_SA_DQ<0>")
	)
	(segment
		(start 303.763172 -316.739016)
		(end 300.540674 -316.739016)
		(width 0.18288)
		(layer "In2.Cu")
		(net "M_B_CPU0_SA_DQ<0>")
	)
	(segment
		(start 337.153758 -276.709886)
		(end 337.42122 -276.709886)
		(width 0.088646)
		(layer "In2.Cu")
		(net "M_B_CPU0_SA_DQ<0>")
	)
	(segment
		(start 337.134962 -276.708616)
		(end 337.152488 -276.708616)
		(width 0.088646)
		(layer "In2.Cu")
		(net "M_B_CPU0_SA_DQ<0>")
	)
	(segment
		(start 336.099912 -280.759662)
		(end 336.099912 -280.778204)
		(width 0.088646)
		(layer "In2.Cu")
		(net "M_B_CPU0_SA_DQ<0>")
	)
	(segment
		(start 334.51165 -281.911298)
		(end 334.50276 -281.916378)
		(width 0.088646)
		(layer "In2.Cu")
		(net "M_B_CPU0_SA_DQ<0>")
	)
	(segment
		(start 335.92135 -281.097482)
		(end 335.91246 -281.102562)
		(width 0.088646)
		(layer "In2.Cu")
		(net "M_B_CPU0_SA_DQ<0>")
	)
	(segment
		(start 334.97266 -281.102562)
		(end 334.966564 -281.106118)
		(width 0.088646)
		(layer "In2.Cu")
		(net "M_B_CPU0_SA_DQ<0>")
	)
	(segment
		(start 299.816012 -315.647832)
		(end 299.209968 -315.041788)
		(width 0.18288)
		(layer "In2.Cu")
		(net "M_B_CPU0_SA_DQ<0>")
	)
	(segment
		(start 307.175154 -316.898274)
		(end 307.01869 -316.74181)
		(width 0.18288)
		(layer "In2.Cu")
		(net "M_B_CPU0_SA_DQ<0>")
	)
	(segment
		(start 311.688734 -315.852048)
		(end 311.02681 -316.513972)
		(width 0.18288)
		(layer "In2.Cu")
		(net "M_B_CPU0_SA_DQ<0>")
	)
	(segment
		(start 309.674006 -316.739016)
		(end 307.56479 -316.739016)
		(width 0.18288)
		(layer "In2.Cu")
		(net "M_B_CPU0_SA_DQ<0>")
	)
	(segment
		(start 303.911508 -316.887352)
		(end 303.763172 -316.739016)
		(width 0.18288)
		(layer "In2.Cu")
		(net "M_B_CPU0_SA_DQ<0>")
	)
	(segment
		(start 304.464466 -316.887352)
		(end 303.911508 -316.887352)
		(width 0.18288)
		(layer "In2.Cu")
		(net "M_B_CPU0_SA_DQ<0>")
	)
	(segment
		(start 336.39125 -280.283412)
		(end 336.38236 -280.288492)
		(width 0.088646)
		(layer "In2.Cu")
		(net "M_B_CPU0_SA_DQ<0>")
	)
	(segment
		(start 337.509612 -278.31796)
		(end 337.509612 -278.336502)
		(width 0.088646)
		(layer "In2.Cu")
		(net "M_B_CPU0_SA_DQ<0>")
	)
	(segment
		(start 298.258992 -315.041788)
		(end 298.23791 -315.06287)
		(width 0.18288)
		(layer "In2.Cu")
		(net "M_B_CPU0_SA_DQ<0>")
	)
	(segment
		(start 333.845662 -281.840686)
		(end 333.22133 -281.840686)
		(width 0.088646)
		(layer "In2.Cu")
		(net "M_B_CPU0_SA_DQ<0>")
	)
	(segment
		(start 307.405532 -316.898274)
		(end 307.175154 -316.898274)
		(width 0.18288)
		(layer "In2.Cu")
		(net "M_B_CPU0_SA_DQ<0>")
	)
	(segment
		(start 315.074046 -314.956698)
		(end 314.178696 -315.852048)
		(width 0.18288)
		(layer "In2.Cu")
		(net "M_B_CPU0_SA_DQ<0>")
	)
	(segment
		(start 335.538064 -281.102562)
		(end 335.523332 -281.093926)
		(width 0.088646)
		(layer "In2.Cu")
		(net "M_B_CPU0_SA_DQ<0>")
	)
	(segment
		(start 332.506066 -282.55595)
		(end 332.506066 -285.477966)
		(width 0.18288)
		(layer "In2.Cu")
		(net "M_B_CPU0_SA_DQ<0>")
	)
	(segment
		(start 333.006446 -282.05557)
		(end 332.506066 -282.55595)
		(width 0.18288)
		(layer "In2.Cu")
		(net "M_B_CPU0_SA_DQ<0>")
	)
	(segment
		(start 337.42122 -276.709886)
		(end 337.518248 -276.806914)
		(width 0.088646)
		(layer "In2.Cu")
		(net "M_B_CPU0_SA_DQ<0>")
	)
	(segment
		(start 336.569812 -279.954228)
		(end 336.569812 -279.964134)
		(width 0.088646)
		(layer "In2.Cu")
		(net "M_B_CPU0_SA_DQ<0>")
	)
	(segment
		(start 298.23791 -315.06287)
		(end 296.780966 -315.06287)
		(width 0.18288)
		(layer "In2.Cu")
		(net "M_B_CPU0_SA_DQ<0>")
	)
	(segment
		(start 306.277518 -316.74181)
		(end 306.176934 -316.641226)
		(width 0.18288)
		(layer "In2.Cu")
		(net "M_B_CPU0_SA_DQ<0>")
	)
	(segment
		(start 314.178696 -315.852048)
		(end 311.688734 -315.852048)
		(width 0.18288)
		(layer "In2.Cu")
		(net "M_B_CPU0_SA_DQ<0>")
	)
	(segment
		(start 306.176934 -316.641226)
		(end 304.710592 -316.641226)
		(width 0.18288)
		(layer "In2.Cu")
		(net "M_B_CPU0_SA_DQ<0>")
	)
	(segment
		(start 300.075092 -316.273434)
		(end 299.816012 -315.647832)
		(width 0.18288)
		(layer "In2.Cu")
		(net "M_B_CPU0_SA_DQ<0>")
	)
	(segment
		(start 332.317598 -285.932372)
		(end 331.90434 -286.929068)
		(width 0.18288)
		(layer "In2.Cu")
		(net "M_B_CPU0_SA_DQ<0>")
	)
	(arc
		(start 337.32216 -278.66086)
		(mid 337.117825 -278.863465)
		(end 337.039712 -279.140412)
		(width 0.088646)
		(layer "In2.Cu")
		(net "M_B_CPU0_SA_DQ<0>")
	)
	(arc
		(start 337.039712 -279.150318)
		(mid 336.992033 -279.333218)
		(end 336.86115 -279.469596)
		(width 0.088646)
		(layer "In2.Cu")
		(net "M_B_CPU0_SA_DQ<0>")
	)
	(arc
		(start 336.569812 -279.964134)
		(mid 336.522133 -280.147034)
		(end 336.39125 -280.283412)
		(width 0.088646)
		(layer "In2.Cu")
		(net "M_B_CPU0_SA_DQ<0>")
	)
	(arc
		(start 334.966564 -281.106118)
		(mid 334.764151 -281.312531)
		(end 334.690212 -281.59202)
		(width 0.088646)
		(layer "In2.Cu")
		(net "M_B_CPU0_SA_DQ<0>")
	)
	(arc
		(start 334.50276 -281.916378)
		(mid 334.315562 -281.966521)
		(end 334.128364 -281.916378)
		(width 0.088646)
		(layer "In2.Cu")
		(net "M_B_CPU0_SA_DQ<0>")
	)
	(arc
		(start 336.099912 -280.778204)
		(mid 336.052233 -280.961104)
		(end 335.92135 -281.097482)
		(width 0.088646)
		(layer "In2.Cu")
		(net "M_B_CPU0_SA_DQ<0>")
	)
	(arc
		(start 337.518248 -276.806914)
		(mid 337.611856 -277.032789)
		(end 337.79206 -277.198074)
		(width 0.088646)
		(layer "In2.Cu")
		(net "M_B_CPU0_SA_DQ<0>")
	)
	(arc
		(start 336.85226 -279.474676)
		(mid 336.647925 -279.677281)
		(end 336.569812 -279.954228)
		(width 0.088646)
		(layer "In2.Cu")
		(net "M_B_CPU0_SA_DQ<0>")
	)
	(arc
		(start 334.690212 -281.59202)
		(mid 334.642533 -281.77492)
		(end 334.51165 -281.911298)
		(width 0.088646)
		(layer "In2.Cu")
		(net "M_B_CPU0_SA_DQ<0>")
	)
	(arc
		(start 336.38236 -280.288492)
		(mid 336.180074 -280.487473)
		(end 336.099912 -280.759662)
		(width 0.088646)
		(layer "In2.Cu")
		(net "M_B_CPU0_SA_DQ<0>")
	)
	(arc
		(start 337.80095 -277.203154)
		(mid 337.979547 -277.522432)
		(end 337.80095 -277.84171)
		(width 0.088646)
		(layer "In2.Cu")
		(net "M_B_CPU0_SA_DQ<0>")
	)
	(arc
		(start 337.79206 -277.84679)
		(mid 337.589774 -278.045771)
		(end 337.509612 -278.31796)
		(width 0.088646)
		(layer "In2.Cu")
		(net "M_B_CPU0_SA_DQ<0>")
	)
	(arc
		(start 334.128364 -281.916378)
		(mid 333.991995 -281.859936)
		(end 333.845662 -281.840686)
		(width 0.088646)
		(layer "In2.Cu")
		(net "M_B_CPU0_SA_DQ<0>")
	)
	(arc
		(start 335.91246 -281.102562)
		(mid 335.725262 -281.152705)
		(end 335.538064 -281.102562)
		(width 0.088646)
		(layer "In2.Cu")
		(net "M_B_CPU0_SA_DQ<0>")
	)
	(arc
		(start 335.523332 -281.093926)
		(mid 335.246857 -281.026606)
		(end 334.97266 -281.102562)
		(width 0.088646)
		(layer "In2.Cu")
		(net "M_B_CPU0_SA_DQ<0>")
	)
	(arc
		(start 337.509612 -278.336502)
		(mid 337.461933 -278.519402)
		(end 337.33105 -278.65578)
		(width 0.088646)
		(layer "In2.Cu")
		(net "M_B_CPU0_SA_DQ<0>")
	)
	(segment
		(start 338.544916 -256.361184)
		(end 338.544662 -256.361438)
		(width 0.20066)
		(layer "F.Cu")
		(net "M_B_CPU0_SA_CS_N<3>")
	)
	(segment
		(start 338.544916 -255.825498)
		(end 338.544916 -256.361184)
		(width 0.20066)
		(layer "F.Cu")
		(net "M_B_CPU0_SA_CS_N<3>")
	)
	(segment
		(start 299.029882 -267.016738)
		(end 297.899582 -267.016738)
		(width 0.20066)
		(layer "F.Cu")
		(net "M_B_CPU0_SA_CS_N<3>")
	)
	(segment
		(start 332.575408 -256.604262)
		(end 332.476602 -256.505456)
		(width 0.088646)
		(layer "In2.Cu")
		(net "M_B_CPU0_SA_CS_N<3>")
	)
	(segment
		(start 304.732944 -265.787124)
		(end 304.516282 -265.570462)
		(width 0.18288)
		(layer "In2.Cu")
		(net "M_B_CPU0_SA_CS_N<3>")
	)
	(segment
		(start 309.432706 -265.272266)
		(end 308.47411 -265.272266)
		(width 0.18288)
		(layer "In2.Cu")
		(net "M_B_CPU0_SA_CS_N<3>")
	)
	(segment
		(start 303.68367 -266.150598)
		(end 303.68367 -266.47902)
		(width 0.18288)
		(layer "In2.Cu")
		(net "M_B_CPU0_SA_CS_N<3>")
	)
	(segment
		(start 306.291996 -265.71829)
		(end 305.892962 -266.117324)
		(width 0.18288)
		(layer "In2.Cu")
		(net "M_B_CPU0_SA_CS_N<3>")
	)
	(segment
		(start 323.333618 -258.660646)
		(end 322.628768 -259.365496)
		(width 0.18288)
		(layer "In2.Cu")
		(net "M_B_CPU0_SA_CS_N<3>")
	)
	(segment
		(start 309.724806 -264.804652)
		(end 309.724806 -264.980166)
		(width 0.18288)
		(layer "In2.Cu")
		(net "M_B_CPU0_SA_CS_N<3>")
	)
	(segment
		(start 313.565286 -264.019792)
		(end 313.174126 -264.410952)
		(width 0.18288)
		(layer "In2.Cu")
		(net "M_B_CPU0_SA_CS_N<3>")
	)
	(segment
		(start 304.846736 -266.117324)
		(end 304.732944 -266.003532)
		(width 0.18288)
		(layer "In2.Cu")
		(net "M_B_CPU0_SA_CS_N<3>")
	)
	(segment
		(start 331.927962 -256.476246)
		(end 331.816202 -256.476246)
		(width 0.088646)
		(layer "In2.Cu")
		(net "M_B_CPU0_SA_CS_N<3>")
	)
	(segment
		(start 307.653436 -264.724642)
		(end 307.16728 -265.210798)
		(width 0.18288)
		(layer "In2.Cu")
		(net "M_B_CPU0_SA_CS_N<3>")
	)
	(segment
		(start 300.936914 -267.06068)
		(end 300.515782 -267.481812)
		(width 0.18288)
		(layer "In2.Cu")
		(net "M_B_CPU0_SA_CS_N<3>")
	)
	(segment
		(start 311.42559 -264.008108)
		(end 311.214008 -264.21969)
		(width 0.18288)
		(layer "In2.Cu")
		(net "M_B_CPU0_SA_CS_N<3>")
	)
	(segment
		(start 315.121036 -262.958834)
		(end 315.121036 -263.289542)
		(width 0.18288)
		(layer "In2.Cu")
		(net "M_B_CPU0_SA_CS_N<3>")
	)
	(segment
		(start 332.858618 -256.721102)
		(end 332.575408 -256.604262)
		(width 0.088646)
		(layer "In2.Cu")
		(net "M_B_CPU0_SA_CS_N<3>")
	)
	(segment
		(start 304.732944 -266.003532)
		(end 304.732944 -265.787124)
		(width 0.18288)
		(layer "In2.Cu")
		(net "M_B_CPU0_SA_CS_N<3>")
	)
	(segment
		(start 328.729086 -258.660646)
		(end 323.333618 -258.660646)
		(width 0.18288)
		(layer "In2.Cu")
		(net "M_B_CPU0_SA_CS_N<3>")
	)
	(segment
		(start 338.388198 -256.632456)
		(end 338.299044 -256.656332)
		(width 0.088646)
		(layer "In2.Cu")
		(net "M_B_CPU0_SA_CS_N<3>")
	)
	(segment
		(start 307.926486 -264.724642)
		(end 307.653436 -264.724642)
		(width 0.18288)
		(layer "In2.Cu")
		(net "M_B_CPU0_SA_CS_N<3>")
	)
	(segment
		(start 311.214008 -264.600182)
		(end 310.901842 -264.912348)
		(width 0.18288)
		(layer "In2.Cu")
		(net "M_B_CPU0_SA_CS_N<3>")
	)
	(segment
		(start 307.16728 -265.43508)
		(end 306.88407 -265.71829)
		(width 0.18288)
		(layer "In2.Cu")
		(net "M_B_CPU0_SA_CS_N<3>")
	)
	(segment
		(start 314.390786 -264.019792)
		(end 313.565286 -264.019792)
		(width 0.18288)
		(layer "In2.Cu")
		(net "M_B_CPU0_SA_CS_N<3>")
	)
	(segment
		(start 304.263806 -265.570462)
		(end 303.68367 -266.150598)
		(width 0.18288)
		(layer "In2.Cu")
		(net "M_B_CPU0_SA_CS_N<3>")
	)
	(segment
		(start 312.430414 -264.410952)
		(end 312.02757 -264.008108)
		(width 0.18288)
		(layer "In2.Cu")
		(net "M_B_CPU0_SA_CS_N<3>")
	)
	(segment
		(start 330.913486 -256.476246)
		(end 328.729086 -258.660646)
		(width 0.18288)
		(layer "In2.Cu")
		(net "M_B_CPU0_SA_CS_N<3>")
	)
	(segment
		(start 332.476602 -256.505456)
		(end 332.476602 -256.37744)
		(width 0.088646)
		(layer "In2.Cu")
		(net "M_B_CPU0_SA_CS_N<3>")
	)
	(segment
		(start 308.47411 -265.272266)
		(end 307.926486 -264.724642)
		(width 0.18288)
		(layer "In2.Cu")
		(net "M_B_CPU0_SA_CS_N<3>")
	)
	(segment
		(start 331.816202 -256.476246)
		(end 330.913486 -256.476246)
		(width 0.18288)
		(layer "In2.Cu")
		(net "M_B_CPU0_SA_CS_N<3>")
	)
	(segment
		(start 315.121036 -263.289542)
		(end 314.390786 -264.019792)
		(width 0.18288)
		(layer "In2.Cu")
		(net "M_B_CPU0_SA_CS_N<3>")
	)
	(segment
		(start 310.55818 -264.912348)
		(end 310.250586 -264.604754)
		(width 0.18288)
		(layer "In2.Cu")
		(net "M_B_CPU0_SA_CS_N<3>")
	)
	(segment
		(start 322.628768 -259.365496)
		(end 315.94679 -262.13308)
		(width 0.18288)
		(layer "In2.Cu")
		(net "M_B_CPU0_SA_CS_N<3>")
	)
	(segment
		(start 332.10119 -256.303018)
		(end 331.927962 -256.476246)
		(width 0.088646)
		(layer "In2.Cu")
		(net "M_B_CPU0_SA_CS_N<3>")
	)
	(segment
		(start 299.62602 -267.016738)
		(end 299.029882 -267.016738)
		(width 0.18288)
		(layer "In2.Cu")
		(net "M_B_CPU0_SA_CS_N<3>")
	)
	(segment
		(start 303.68367 -266.47902)
		(end 302.59401 -267.56868)
		(width 0.18288)
		(layer "In2.Cu")
		(net "M_B_CPU0_SA_CS_N<3>")
	)
	(segment
		(start 332.476602 -256.37744)
		(end 332.40218 -256.303018)
		(width 0.088646)
		(layer "In2.Cu")
		(net "M_B_CPU0_SA_CS_N<3>")
	)
	(segment
		(start 300.515782 -267.481812)
		(end 300.091094 -267.481812)
		(width 0.18288)
		(layer "In2.Cu")
		(net "M_B_CPU0_SA_CS_N<3>")
	)
	(segment
		(start 305.892962 -266.117324)
		(end 304.846736 -266.117324)
		(width 0.18288)
		(layer "In2.Cu")
		(net "M_B_CPU0_SA_CS_N<3>")
	)
	(segment
		(start 338.544662 -256.361438)
		(end 338.388198 -256.632456)
		(width 0.088646)
		(layer "In2.Cu")
		(net "M_B_CPU0_SA_CS_N<3>")
	)
	(segment
		(start 310.250586 -264.604754)
		(end 309.924704 -264.604754)
		(width 0.18288)
		(layer "In2.Cu")
		(net "M_B_CPU0_SA_CS_N<3>")
	)
	(segment
		(start 307.16728 -265.210798)
		(end 307.16728 -265.43508)
		(width 0.18288)
		(layer "In2.Cu")
		(net "M_B_CPU0_SA_CS_N<3>")
	)
	(segment
		(start 310.901842 -264.912348)
		(end 310.55818 -264.912348)
		(width 0.18288)
		(layer "In2.Cu")
		(net "M_B_CPU0_SA_CS_N<3>")
	)
	(segment
		(start 301.767494 -267.06068)
		(end 300.936914 -267.06068)
		(width 0.18288)
		(layer "In2.Cu")
		(net "M_B_CPU0_SA_CS_N<3>")
	)
	(segment
		(start 306.88407 -265.71829)
		(end 306.291996 -265.71829)
		(width 0.18288)
		(layer "In2.Cu")
		(net "M_B_CPU0_SA_CS_N<3>")
	)
	(segment
		(start 300.091094 -267.481812)
		(end 299.62602 -267.016738)
		(width 0.18288)
		(layer "In2.Cu")
		(net "M_B_CPU0_SA_CS_N<3>")
	)
	(segment
		(start 313.174126 -264.410952)
		(end 312.430414 -264.410952)
		(width 0.18288)
		(layer "In2.Cu")
		(net "M_B_CPU0_SA_CS_N<3>")
	)
	(segment
		(start 304.516282 -265.570462)
		(end 304.263806 -265.570462)
		(width 0.18288)
		(layer "In2.Cu")
		(net "M_B_CPU0_SA_CS_N<3>")
	)
	(segment
		(start 309.924704 -264.604754)
		(end 309.724806 -264.804652)
		(width 0.18288)
		(layer "In2.Cu")
		(net "M_B_CPU0_SA_CS_N<3>")
	)
	(segment
		(start 311.214008 -264.21969)
		(end 311.214008 -264.600182)
		(width 0.18288)
		(layer "In2.Cu")
		(net "M_B_CPU0_SA_CS_N<3>")
	)
	(segment
		(start 312.02757 -264.008108)
		(end 311.42559 -264.008108)
		(width 0.18288)
		(layer "In2.Cu")
		(net "M_B_CPU0_SA_CS_N<3>")
	)
	(segment
		(start 309.724806 -264.980166)
		(end 309.432706 -265.272266)
		(width 0.18288)
		(layer "In2.Cu")
		(net "M_B_CPU0_SA_CS_N<3>")
	)
	(segment
		(start 302.275494 -267.56868)
		(end 301.767494 -267.06068)
		(width 0.18288)
		(layer "In2.Cu")
		(net "M_B_CPU0_SA_CS_N<3>")
	)
	(segment
		(start 332.40218 -256.303018)
		(end 332.10119 -256.303018)
		(width 0.088646)
		(layer "In2.Cu")
		(net "M_B_CPU0_SA_CS_N<3>")
	)
	(segment
		(start 315.94679 -262.13308)
		(end 315.121036 -262.958834)
		(width 0.18288)
		(layer "In2.Cu")
		(net "M_B_CPU0_SA_CS_N<3>")
	)
	(segment
		(start 302.59401 -267.56868)
		(end 302.275494 -267.56868)
		(width 0.18288)
		(layer "In2.Cu")
		(net "M_B_CPU0_SA_CS_N<3>")
	)
	(arc
		(start 336.85226 -256.685796)
		(mid 336.665062 -256.735939)
		(end 336.477864 -256.685796)
		(width 0.088646)
		(layer "In2.Cu")
		(net "M_B_CPU0_SA_CS_N<3>")
	)
	(arc
		(start 335.538064 -256.685796)
		(mid 335.255362 -256.61002)
		(end 334.97266 -256.685796)
		(width 0.088646)
		(layer "In2.Cu")
		(net "M_B_CPU0_SA_CS_N<3>")
	)
	(arc
		(start 338.299044 -256.656332)
		(mid 338.042045 -256.610885)
		(end 337.79206 -256.685796)
		(width 0.088646)
		(layer "In2.Cu")
		(net "M_B_CPU0_SA_CS_N<3>")
	)
	(arc
		(start 332.946502 -256.733802)
		(mid 332.901766 -256.732966)
		(end 332.858618 -256.721102)
		(width 0.088646)
		(layer "In2.Cu")
		(net "M_B_CPU0_SA_CS_N<3>")
	)
	(arc
		(start 333.09306 -256.685796)
		(mid 333.022281 -256.717435)
		(end 332.946502 -256.733802)
		(width 0.088646)
		(layer "In2.Cu")
		(net "M_B_CPU0_SA_CS_N<3>")
	)
	(arc
		(start 334.97266 -256.685796)
		(mid 334.785462 -256.735939)
		(end 334.598264 -256.685796)
		(width 0.088646)
		(layer "In2.Cu")
		(net "M_B_CPU0_SA_CS_N<3>")
	)
	(arc
		(start 334.03286 -256.685796)
		(mid 333.845662 -256.735939)
		(end 333.658464 -256.685796)
		(width 0.088646)
		(layer "In2.Cu")
		(net "M_B_CPU0_SA_CS_N<3>")
	)
	(arc
		(start 336.477864 -256.685796)
		(mid 336.195162 -256.61002)
		(end 335.91246 -256.685796)
		(width 0.088646)
		(layer "In2.Cu")
		(net "M_B_CPU0_SA_CS_N<3>")
	)
	(arc
		(start 337.417664 -256.685796)
		(mid 337.134962 -256.61002)
		(end 336.85226 -256.685796)
		(width 0.088646)
		(layer "In2.Cu")
		(net "M_B_CPU0_SA_CS_N<3>")
	)
	(arc
		(start 334.598264 -256.685796)
		(mid 334.315562 -256.61002)
		(end 334.03286 -256.685796)
		(width 0.088646)
		(layer "In2.Cu")
		(net "M_B_CPU0_SA_CS_N<3>")
	)
	(arc
		(start 335.91246 -256.685796)
		(mid 335.725262 -256.735939)
		(end 335.538064 -256.685796)
		(width 0.088646)
		(layer "In2.Cu")
		(net "M_B_CPU0_SA_CS_N<3>")
	)
	(arc
		(start 333.658464 -256.685796)
		(mid 333.375762 -256.61002)
		(end 333.09306 -256.685796)
		(width 0.088646)
		(layer "In2.Cu")
		(net "M_B_CPU0_SA_CS_N<3>")
	)
	(arc
		(start 337.79206 -256.685796)
		(mid 337.604862 -256.735939)
		(end 337.417664 -256.685796)
		(width 0.088646)
		(layer "In2.Cu")
		(net "M_B_CPU0_SA_CS_N<3>")
	)
	(segment
		(start 294.904414 -267.866622)
		(end 293.799514 -267.866622)
		(width 0.20066)
		(layer "F.Cu")
		(net "M_B_CPU0_SA_CS_N<2>")
	)
	(segment
		(start 338.074762 -257.175254)
		(end 338.074762 -256.639314)
		(width 0.20066)
		(layer "F.Cu")
		(net "M_B_CPU0_SA_CS_N<2>")
	)
	(segment
		(start 297.008042 -267.3985)
		(end 296.63009 -267.3985)
		(width 0.18288)
		(layer "In2.Cu")
		(net "M_B_CPU0_SA_CS_N<2>")
	)
	(segment
		(start 338.074762 -257.175254)
		(end 338.231226 -256.904236)
		(width 0.088646)
		(layer "In2.Cu")
		(net "M_B_CPU0_SA_CS_N<2>")
	)
	(segment
		(start 295.199562 -267.571474)
		(end 294.904414 -267.866622)
		(width 0.18288)
		(layer "In2.Cu")
		(net "M_B_CPU0_SA_CS_N<2>")
	)
	(segment
		(start 295.820084 -267.935202)
		(end 295.456356 -267.571474)
		(width 0.18288)
		(layer "In2.Cu")
		(net "M_B_CPU0_SA_CS_N<2>")
	)
	(segment
		(start 299.24629 -267.44168)
		(end 298.339002 -267.44168)
		(width 0.18288)
		(layer "In2.Cu")
		(net "M_B_CPU0_SA_CS_N<2>")
	)
	(segment
		(start 316.846204 -262.318754)
		(end 314.244482 -264.918952)
		(width 0.18288)
		(layer "In2.Cu")
		(net "M_B_CPU0_SA_CS_N<2>")
	)
	(segment
		(start 300.825662 -268.243304)
		(end 300.047914 -268.243304)
		(width 0.18288)
		(layer "In2.Cu")
		(net "M_B_CPU0_SA_CS_N<2>")
	)
	(segment
		(start 298.178728 -267.601954)
		(end 297.211496 -267.601954)
		(width 0.18288)
		(layer "In2.Cu")
		(net "M_B_CPU0_SA_CS_N<2>")
	)
	(segment
		(start 300.047914 -268.243304)
		(end 299.24629 -267.44168)
		(width 0.18288)
		(layer "In2.Cu")
		(net "M_B_CPU0_SA_CS_N<2>")
	)
	(segment
		(start 298.339002 -267.44168)
		(end 298.178728 -267.601954)
		(width 0.18288)
		(layer "In2.Cu")
		(net "M_B_CPU0_SA_CS_N<2>")
	)
	(segment
		(start 307.569108 -265.780266)
		(end 306.72405 -266.625324)
		(width 0.18288)
		(layer "In2.Cu")
		(net "M_B_CPU0_SA_CS_N<2>")
	)
	(segment
		(start 304.256186 -266.625324)
		(end 302.638206 -268.243304)
		(width 0.18288)
		(layer "In2.Cu")
		(net "M_B_CPU0_SA_CS_N<2>")
	)
	(segment
		(start 310.134 -265.780266)
		(end 307.569108 -265.780266)
		(width 0.18288)
		(layer "In2.Cu")
		(net "M_B_CPU0_SA_CS_N<2>")
	)
	(segment
		(start 328.872342 -259.006086)
		(end 323.706998 -259.006086)
		(width 0.18288)
		(layer "In2.Cu")
		(net "M_B_CPU0_SA_CS_N<2>")
	)
	(segment
		(start 302.638206 -268.243304)
		(end 301.892208 -268.243304)
		(width 0.18288)
		(layer "In2.Cu")
		(net "M_B_CPU0_SA_CS_N<2>")
	)
	(segment
		(start 322.901564 -259.81152)
		(end 316.846204 -262.318754)
		(width 0.18288)
		(layer "In2.Cu")
		(net "M_B_CPU0_SA_CS_N<2>")
	)
	(segment
		(start 338.231226 -256.904236)
		(end 338.210144 -256.826258)
		(width 0.088646)
		(layer "In2.Cu")
		(net "M_B_CPU0_SA_CS_N<2>")
	)
	(segment
		(start 296.63009 -267.3985)
		(end 296.093388 -267.935202)
		(width 0.18288)
		(layer "In2.Cu")
		(net "M_B_CPU0_SA_CS_N<2>")
	)
	(segment
		(start 295.456356 -267.571474)
		(end 295.199562 -267.571474)
		(width 0.18288)
		(layer "In2.Cu")
		(net "M_B_CPU0_SA_CS_N<2>")
	)
	(segment
		(start 301.892208 -268.243304)
		(end 301.529242 -268.60627)
		(width 0.18288)
		(layer "In2.Cu")
		(net "M_B_CPU0_SA_CS_N<2>")
	)
	(segment
		(start 296.093388 -267.935202)
		(end 295.820084 -267.935202)
		(width 0.18288)
		(layer "In2.Cu")
		(net "M_B_CPU0_SA_CS_N<2>")
	)
	(segment
		(start 314.244482 -264.918952)
		(end 312.213498 -264.918952)
		(width 0.18288)
		(layer "In2.Cu")
		(net "M_B_CPU0_SA_CS_N<2>")
	)
	(segment
		(start 312.213498 -264.918952)
		(end 310.134 -265.780266)
		(width 0.18288)
		(layer "In2.Cu")
		(net "M_B_CPU0_SA_CS_N<2>")
	)
	(segment
		(start 331.053694 -256.824734)
		(end 328.872342 -259.006086)
		(width 0.18288)
		(layer "In2.Cu")
		(net "M_B_CPU0_SA_CS_N<2>")
	)
	(segment
		(start 331.816202 -256.824734)
		(end 331.053694 -256.824734)
		(width 0.18288)
		(layer "In2.Cu")
		(net "M_B_CPU0_SA_CS_N<2>")
	)
	(segment
		(start 301.188628 -268.60627)
		(end 300.825662 -268.243304)
		(width 0.18288)
		(layer "In2.Cu")
		(net "M_B_CPU0_SA_CS_N<2>")
	)
	(segment
		(start 323.706998 -259.006086)
		(end 322.901564 -259.81152)
		(width 0.18288)
		(layer "In2.Cu")
		(net "M_B_CPU0_SA_CS_N<2>")
	)
	(segment
		(start 332.525878 -256.824734)
		(end 331.816202 -256.824734)
		(width 0.088646)
		(layer "In2.Cu")
		(net "M_B_CPU0_SA_CS_N<2>")
	)
	(segment
		(start 297.211496 -267.601954)
		(end 297.008042 -267.3985)
		(width 0.18288)
		(layer "In2.Cu")
		(net "M_B_CPU0_SA_CS_N<2>")
	)
	(segment
		(start 301.529242 -268.60627)
		(end 301.188628 -268.60627)
		(width 0.18288)
		(layer "In2.Cu")
		(net "M_B_CPU0_SA_CS_N<2>")
	)
	(segment
		(start 306.72405 -266.625324)
		(end 304.256186 -266.625324)
		(width 0.18288)
		(layer "In2.Cu")
		(net "M_B_CPU0_SA_CS_N<2>")
	)
	(arc
		(start 333.56296 -256.850896)
		(mid 333.375762 -256.800753)
		(end 333.188564 -256.850896)
		(width 0.088646)
		(layer "In2.Cu")
		(net "M_B_CPU0_SA_CS_N<2>")
	)
	(arc
		(start 333.188564 -256.850896)
		(mid 332.905862 -256.926672)
		(end 332.62316 -256.850896)
		(width 0.088646)
		(layer "In2.Cu")
		(net "M_B_CPU0_SA_CS_N<2>")
	)
	(arc
		(start 332.62316 -256.850896)
		(mid 332.576245 -256.831399)
		(end 332.525878 -256.824734)
		(width 0.088646)
		(layer "In2.Cu")
		(net "M_B_CPU0_SA_CS_N<2>")
	)
	(arc
		(start 335.068164 -256.850896)
		(mid 334.785462 -256.926672)
		(end 334.50276 -256.850896)
		(width 0.088646)
		(layer "In2.Cu")
		(net "M_B_CPU0_SA_CS_N<2>")
	)
	(arc
		(start 336.947764 -256.850896)
		(mid 336.665062 -256.926672)
		(end 336.38236 -256.850896)
		(width 0.088646)
		(layer "In2.Cu")
		(net "M_B_CPU0_SA_CS_N<2>")
	)
	(arc
		(start 337.32216 -256.850896)
		(mid 337.134962 -256.800753)
		(end 336.947764 -256.850896)
		(width 0.088646)
		(layer "In2.Cu")
		(net "M_B_CPU0_SA_CS_N<2>")
	)
	(arc
		(start 334.50276 -256.850896)
		(mid 334.315562 -256.800753)
		(end 334.128364 -256.850896)
		(width 0.088646)
		(layer "In2.Cu")
		(net "M_B_CPU0_SA_CS_N<2>")
	)
	(arc
		(start 336.007964 -256.850896)
		(mid 335.725262 -256.926672)
		(end 335.44256 -256.850896)
		(width 0.088646)
		(layer "In2.Cu")
		(net "M_B_CPU0_SA_CS_N<2>")
	)
	(arc
		(start 338.210144 -256.826258)
		(mid 338.046048 -256.801911)
		(end 337.887564 -256.850896)
		(width 0.088646)
		(layer "In2.Cu")
		(net "M_B_CPU0_SA_CS_N<2>")
	)
	(arc
		(start 335.44256 -256.850896)
		(mid 335.255362 -256.800753)
		(end 335.068164 -256.850896)
		(width 0.088646)
		(layer "In2.Cu")
		(net "M_B_CPU0_SA_CS_N<2>")
	)
	(arc
		(start 336.38236 -256.850896)
		(mid 336.195162 -256.800753)
		(end 336.007964 -256.850896)
		(width 0.088646)
		(layer "In2.Cu")
		(net "M_B_CPU0_SA_CS_N<2>")
	)
	(arc
		(start 334.128364 -256.850896)
		(mid 333.845662 -256.926672)
		(end 333.56296 -256.850896)
		(width 0.088646)
		(layer "In2.Cu")
		(net "M_B_CPU0_SA_CS_N<2>")
	)
	(arc
		(start 337.887564 -256.850896)
		(mid 337.604862 -256.926672)
		(end 337.32216 -256.850896)
		(width 0.088646)
		(layer "In2.Cu")
		(net "M_B_CPU0_SA_CS_N<2>")
	)
	(segment
		(start 336.665316 -255.825498)
		(end 336.665316 -256.361184)
		(width 0.20066)
		(layer "F.Cu")
		(net "M_B_CPU0_SA_CS_N<1>")
	)
	(segment
		(start 291.460682 -267.016738)
		(end 290.355782 -267.016738)
		(width 0.20066)
		(layer "F.Cu")
		(net "M_B_CPU0_SA_CS_N<1>")
	)
	(segment
		(start 336.665316 -256.361184)
		(end 336.665062 -256.361438)
		(width 0.20066)
		(layer "F.Cu")
		(net "M_B_CPU0_SA_CS_N<1>")
	)
	(segment
		(start 291.711126 -267.016738)
		(end 291.460682 -267.016738)
		(width 0.18288)
		(layer "In2.Cu")
		(net "M_B_CPU0_SA_CS_N<1>")
	)
	(segment
		(start 306.071524 -264.946892)
		(end 305.634136 -264.509504)
		(width 0.18288)
		(layer "In2.Cu")
		(net "M_B_CPU0_SA_CS_N<1>")
	)
	(segment
		(start 311.830974 -263.500108)
		(end 311.318402 -263.500108)
		(width 0.18288)
		(layer "In2.Cu")
		(net "M_B_CPU0_SA_CS_N<1>")
	)
	(segment
		(start 297.38193 -266.251944)
		(end 296.79519 -266.838684)
		(width 0.18288)
		(layer "In2.Cu")
		(net "M_B_CPU0_SA_CS_N<1>")
	)
	(segment
		(start 292.818566 -264.816082)
		(end 292.268656 -264.816082)
		(width 0.18288)
		(layer "In2.Cu")
		(net "M_B_CPU0_SA_CS_N<1>")
	)
	(segment
		(start 305.316636 -264.509504)
		(end 304.879248 -264.946892)
		(width 0.18288)
		(layer "In2.Cu")
		(net "M_B_CPU0_SA_CS_N<1>")
	)
	(segment
		(start 313.827668 -263.212834)
		(end 313.509406 -263.212834)
		(width 0.18288)
		(layer "In2.Cu")
		(net "M_B_CPU0_SA_CS_N<1>")
	)
	(segment
		(start 293.197026 -267.300456)
		(end 293.197026 -266.753086)
		(width 0.18288)
		(layer "In2.Cu")
		(net "M_B_CPU0_SA_CS_N<1>")
	)
	(segment
		(start 332.435962 -256.112772)
		(end 331.816202 -256.112772)
		(width 0.088646)
		(layer "In2.Cu")
		(net "M_B_CPU0_SA_CS_N<1>")
	)
	(segment
		(start 331.816202 -256.112772)
		(end 330.788264 -256.112772)
		(width 0.18288)
		(layer "In2.Cu")
		(net "M_B_CPU0_SA_CS_N<1>")
	)
	(segment
		(start 311.318402 -263.500108)
		(end 311.110122 -263.586468)
		(width 0.18288)
		(layer "In2.Cu")
		(net "M_B_CPU0_SA_CS_N<1>")
	)
	(segment
		(start 308.167024 -264.088372)
		(end 307.408326 -264.088372)
		(width 0.18288)
		(layer "In2.Cu")
		(net "M_B_CPU0_SA_CS_N<1>")
	)
	(segment
		(start 293.154862 -265.152378)
		(end 292.818566 -264.816082)
		(width 0.18288)
		(layer "In2.Cu")
		(net "M_B_CPU0_SA_CS_N<1>")
	)
	(segment
		(start 302.562768 -266.55268)
		(end 300.449488 -266.55268)
		(width 0.18288)
		(layer "In2.Cu")
		(net "M_B_CPU0_SA_CS_N<1>")
	)
	(segment
		(start 313.105546 -262.808974)
		(end 312.805826 -262.808974)
		(width 0.18288)
		(layer "In2.Cu")
		(net "M_B_CPU0_SA_CS_N<1>")
	)
	(segment
		(start 293.841932 -267.46708)
		(end 293.36365 -267.46708)
		(width 0.18288)
		(layer "In2.Cu")
		(net "M_B_CPU0_SA_CS_N<1>")
	)
	(segment
		(start 295.543224 -266.398756)
		(end 295.350184 -266.591796)
		(width 0.18288)
		(layer "In2.Cu")
		(net "M_B_CPU0_SA_CS_N<1>")
	)
	(segment
		(start 296.246804 -266.645644)
		(end 296.246804 -266.153646)
		(width 0.18288)
		(layer "In2.Cu")
		(net "M_B_CPU0_SA_CS_N<1>")
	)
	(segment
		(start 306.684426 -264.946892)
		(end 306.071524 -264.946892)
		(width 0.18288)
		(layer "In2.Cu")
		(net "M_B_CPU0_SA_CS_N<1>")
	)
	(segment
		(start 293.197026 -266.753086)
		(end 293.003986 -266.560046)
		(width 0.18288)
		(layer "In2.Cu")
		(net "M_B_CPU0_SA_CS_N<1>")
	)
	(segment
		(start 292.824662 -266.560046)
		(end 292.631622 -266.367006)
		(width 0.18288)
		(layer "In2.Cu")
		(net "M_B_CPU0_SA_CS_N<1>")
	)
	(segment
		(start 314.613036 -262.89)
		(end 314.19546 -263.307576)
		(width 0.18288)
		(layer "In2.Cu")
		(net "M_B_CPU0_SA_CS_N<1>")
	)
	(segment
		(start 298.447714 -266.591542)
		(end 298.108116 -266.251944)
		(width 0.18288)
		(layer "In2.Cu")
		(net "M_B_CPU0_SA_CS_N<1>")
	)
	(segment
		(start 336.508598 -256.09042)
		(end 336.419444 -256.066544)
		(width 0.088646)
		(layer "In2.Cu")
		(net "M_B_CPU0_SA_CS_N<1>")
	)
	(segment
		(start 307.408326 -264.088372)
		(end 307.064156 -264.432542)
		(width 0.18288)
		(layer "In2.Cu")
		(net "M_B_CPU0_SA_CS_N<1>")
	)
	(segment
		(start 336.665062 -256.361438)
		(end 336.508598 -256.09042)
		(width 0.088646)
		(layer "In2.Cu")
		(net "M_B_CPU0_SA_CS_N<1>")
	)
	(segment
		(start 307.064156 -264.567162)
		(end 306.684426 -264.946892)
		(width 0.18288)
		(layer "In2.Cu")
		(net "M_B_CPU0_SA_CS_N<1>")
	)
	(segment
		(start 293.154862 -265.51509)
		(end 293.154862 -265.152378)
		(width 0.18288)
		(layer "In2.Cu")
		(net "M_B_CPU0_SA_CS_N<1>")
	)
	(segment
		(start 308.89575 -263.677146)
		(end 308.57825 -263.677146)
		(width 0.18288)
		(layer "In2.Cu")
		(net "M_B_CPU0_SA_CS_N<1>")
	)
	(segment
		(start 312.805826 -262.808974)
		(end 312.401966 -263.212834)
		(width 0.18288)
		(layer "In2.Cu")
		(net "M_B_CPU0_SA_CS_N<1>")
	)
	(segment
		(start 293.36365 -267.46708)
		(end 293.197026 -267.300456)
		(width 0.18288)
		(layer "In2.Cu")
		(net "M_B_CPU0_SA_CS_N<1>")
	)
	(segment
		(start 299.186092 -266.591542)
		(end 298.447714 -266.591542)
		(width 0.18288)
		(layer "In2.Cu")
		(net "M_B_CPU0_SA_CS_N<1>")
	)
	(segment
		(start 298.108116 -266.251944)
		(end 297.38193 -266.251944)
		(width 0.18288)
		(layer "In2.Cu")
		(net "M_B_CPU0_SA_CS_N<1>")
	)
	(segment
		(start 309.306976 -264.088372)
		(end 308.89575 -263.677146)
		(width 0.18288)
		(layer "In2.Cu")
		(net "M_B_CPU0_SA_CS_N<1>")
	)
	(segment
		(start 293.003986 -266.560046)
		(end 292.824662 -266.560046)
		(width 0.18288)
		(layer "In2.Cu")
		(net "M_B_CPU0_SA_CS_N<1>")
	)
	(segment
		(start 311.110122 -263.586468)
		(end 310.608218 -264.088372)
		(width 0.18288)
		(layer "In2.Cu")
		(net "M_B_CPU0_SA_CS_N<1>")
	)
	(segment
		(start 295.774364 -265.960606)
		(end 295.543224 -266.191746)
		(width 0.18288)
		(layer "In2.Cu")
		(net "M_B_CPU0_SA_CS_N<1>")
	)
	(segment
		(start 330.788264 -256.112772)
		(end 328.58583 -258.315206)
		(width 0.18288)
		(layer "In2.Cu")
		(net "M_B_CPU0_SA_CS_N<1>")
	)
	(segment
		(start 300.449488 -266.55268)
		(end 300.200568 -266.30376)
		(width 0.18288)
		(layer "In2.Cu")
		(net "M_B_CPU0_SA_CS_N<1>")
	)
	(segment
		(start 307.064156 -264.432542)
		(end 307.064156 -264.567162)
		(width 0.18288)
		(layer "In2.Cu")
		(net "M_B_CPU0_SA_CS_N<1>")
	)
	(segment
		(start 296.246804 -266.153646)
		(end 296.053764 -265.960606)
		(width 0.18288)
		(layer "In2.Cu")
		(net "M_B_CPU0_SA_CS_N<1>")
	)
	(segment
		(start 308.57825 -263.677146)
		(end 308.167024 -264.088372)
		(width 0.18288)
		(layer "In2.Cu")
		(net "M_B_CPU0_SA_CS_N<1>")
	)
	(segment
		(start 314.613036 -262.748014)
		(end 314.613036 -262.89)
		(width 0.18288)
		(layer "In2.Cu")
		(net "M_B_CPU0_SA_CS_N<1>")
	)
	(segment
		(start 296.053764 -265.960606)
		(end 295.774364 -265.960606)
		(width 0.18288)
		(layer "In2.Cu")
		(net "M_B_CPU0_SA_CS_N<1>")
	)
	(segment
		(start 292.268656 -264.816082)
		(end 291.904166 -265.180572)
		(width 0.18288)
		(layer "In2.Cu")
		(net "M_B_CPU0_SA_CS_N<1>")
	)
	(segment
		(start 315.6585 -261.70255)
		(end 314.613036 -262.748014)
		(width 0.18288)
		(layer "In2.Cu")
		(net "M_B_CPU0_SA_CS_N<1>")
	)
	(segment
		(start 294.001952 -267.30706)
		(end 293.841932 -267.46708)
		(width 0.18288)
		(layer "In2.Cu")
		(net "M_B_CPU0_SA_CS_N<1>")
	)
	(segment
		(start 310.608218 -264.088372)
		(end 309.306976 -264.088372)
		(width 0.18288)
		(layer "In2.Cu")
		(net "M_B_CPU0_SA_CS_N<1>")
	)
	(segment
		(start 296.439844 -266.838684)
		(end 296.246804 -266.645644)
		(width 0.18288)
		(layer "In2.Cu")
		(net "M_B_CPU0_SA_CS_N<1>")
	)
	(segment
		(start 313.92241 -263.307576)
		(end 313.827668 -263.212834)
		(width 0.18288)
		(layer "In2.Cu")
		(net "M_B_CPU0_SA_CS_N<1>")
	)
	(segment
		(start 304.879248 -264.946892)
		(end 304.168556 -264.946892)
		(width 0.18288)
		(layer "In2.Cu")
		(net "M_B_CPU0_SA_CS_N<1>")
	)
	(segment
		(start 291.904166 -266.823698)
		(end 291.711126 -267.016738)
		(width 0.18288)
		(layer "In2.Cu")
		(net "M_B_CPU0_SA_CS_N<1>")
	)
	(segment
		(start 294.165274 -266.591796)
		(end 294.001952 -266.755118)
		(width 0.18288)
		(layer "In2.Cu")
		(net "M_B_CPU0_SA_CS_N<1>")
	)
	(segment
		(start 294.001952 -266.755118)
		(end 294.001952 -267.30706)
		(width 0.18288)
		(layer "In2.Cu")
		(net "M_B_CPU0_SA_CS_N<1>")
	)
	(segment
		(start 291.904166 -265.180572)
		(end 291.904166 -266.823698)
		(width 0.18288)
		(layer "In2.Cu")
		(net "M_B_CPU0_SA_CS_N<1>")
	)
	(segment
		(start 305.634136 -264.509504)
		(end 305.316636 -264.509504)
		(width 0.18288)
		(layer "In2.Cu")
		(net "M_B_CPU0_SA_CS_N<1>")
	)
	(segment
		(start 295.350184 -266.591796)
		(end 294.165274 -266.591796)
		(width 0.18288)
		(layer "In2.Cu")
		(net "M_B_CPU0_SA_CS_N<1>")
	)
	(segment
		(start 299.473874 -266.30376)
		(end 299.186092 -266.591542)
		(width 0.18288)
		(layer "In2.Cu")
		(net "M_B_CPU0_SA_CS_N<1>")
	)
	(segment
		(start 313.509406 -263.212834)
		(end 313.105546 -262.808974)
		(width 0.18288)
		(layer "In2.Cu")
		(net "M_B_CPU0_SA_CS_N<1>")
	)
	(segment
		(start 312.401966 -263.212834)
		(end 312.118248 -263.212834)
		(width 0.18288)
		(layer "In2.Cu")
		(net "M_B_CPU0_SA_CS_N<1>")
	)
	(segment
		(start 322.960238 -258.315206)
		(end 322.343526 -258.931918)
		(width 0.18288)
		(layer "In2.Cu")
		(net "M_B_CPU0_SA_CS_N<1>")
	)
	(segment
		(start 304.168556 -264.946892)
		(end 302.562768 -266.55268)
		(width 0.18288)
		(layer "In2.Cu")
		(net "M_B_CPU0_SA_CS_N<1>")
	)
	(segment
		(start 314.19546 -263.307576)
		(end 313.92241 -263.307576)
		(width 0.18288)
		(layer "In2.Cu")
		(net "M_B_CPU0_SA_CS_N<1>")
	)
	(segment
		(start 328.58583 -258.315206)
		(end 322.960238 -258.315206)
		(width 0.18288)
		(layer "In2.Cu")
		(net "M_B_CPU0_SA_CS_N<1>")
	)
	(segment
		(start 312.118248 -263.212834)
		(end 311.830974 -263.500108)
		(width 0.18288)
		(layer "In2.Cu")
		(net "M_B_CPU0_SA_CS_N<1>")
	)
	(segment
		(start 322.343526 -258.931918)
		(end 315.6585 -261.70255)
		(width 0.18288)
		(layer "In2.Cu")
		(net "M_B_CPU0_SA_CS_N<1>")
	)
	(segment
		(start 295.543224 -266.191746)
		(end 295.543224 -266.398756)
		(width 0.18288)
		(layer "In2.Cu")
		(net "M_B_CPU0_SA_CS_N<1>")
	)
	(segment
		(start 292.631622 -266.03833)
		(end 293.154862 -265.51509)
		(width 0.18288)
		(layer "In2.Cu")
		(net "M_B_CPU0_SA_CS_N<1>")
	)
	(segment
		(start 292.631622 -266.367006)
		(end 292.631622 -266.03833)
		(width 0.18288)
		(layer "In2.Cu")
		(net "M_B_CPU0_SA_CS_N<1>")
	)
	(segment
		(start 300.200568 -266.30376)
		(end 299.473874 -266.30376)
		(width 0.18288)
		(layer "In2.Cu")
		(net "M_B_CPU0_SA_CS_N<1>")
	)
	(segment
		(start 296.79519 -266.838684)
		(end 296.439844 -266.838684)
		(width 0.18288)
		(layer "In2.Cu")
		(net "M_B_CPU0_SA_CS_N<1>")
	)
	(arc
		(start 334.03286 -256.03708)
		(mid 333.845662 -255.986937)
		(end 333.658464 -256.03708)
		(width 0.088646)
		(layer "In2.Cu")
		(net "M_B_CPU0_SA_CS_N<1>")
	)
	(arc
		(start 335.91246 -256.03708)
		(mid 335.725262 -255.986937)
		(end 335.538064 -256.03708)
		(width 0.088646)
		(layer "In2.Cu")
		(net "M_B_CPU0_SA_CS_N<1>")
	)
	(arc
		(start 333.09306 -256.03708)
		(mid 332.905862 -255.986937)
		(end 332.718664 -256.03708)
		(width 0.088646)
		(layer "In2.Cu")
		(net "M_B_CPU0_SA_CS_N<1>")
	)
	(arc
		(start 332.718664 -256.03708)
		(mid 332.582295 -256.093522)
		(end 332.435962 -256.112772)
		(width 0.088646)
		(layer "In2.Cu")
		(net "M_B_CPU0_SA_CS_N<1>")
	)
	(arc
		(start 336.419444 -256.066544)
		(mid 336.162445 -256.111991)
		(end 335.91246 -256.03708)
		(width 0.088646)
		(layer "In2.Cu")
		(net "M_B_CPU0_SA_CS_N<1>")
	)
	(arc
		(start 334.97266 -256.03708)
		(mid 334.785462 -255.986937)
		(end 334.598264 -256.03708)
		(width 0.088646)
		(layer "In2.Cu")
		(net "M_B_CPU0_SA_CS_N<1>")
	)
	(arc
		(start 334.598264 -256.03708)
		(mid 334.315562 -256.112856)
		(end 334.03286 -256.03708)
		(width 0.088646)
		(layer "In2.Cu")
		(net "M_B_CPU0_SA_CS_N<1>")
	)
	(arc
		(start 333.658464 -256.03708)
		(mid 333.375762 -256.112856)
		(end 333.09306 -256.03708)
		(width 0.088646)
		(layer "In2.Cu")
		(net "M_B_CPU0_SA_CS_N<1>")
	)
	(arc
		(start 335.538064 -256.03708)
		(mid 335.255362 -256.112856)
		(end 334.97266 -256.03708)
		(width 0.088646)
		(layer "In2.Cu")
		(net "M_B_CPU0_SA_CS_N<1>")
	)
	(segment
		(start 287.360614 -267.866622)
		(end 286.255714 -267.866622)
		(width 0.20066)
		(layer "F.Cu")
		(net "M_B_CPU0_SA_CS_N<0>")
	)
	(segment
		(start 337.134962 -257.175254)
		(end 337.134962 -256.639314)
		(width 0.20066)
		(layer "F.Cu")
		(net "M_B_CPU0_SA_CS_N<0>")
	)
	(segment
		(start 288.084514 -268.82344)
		(end 288.084514 -268.458696)
		(width 0.18288)
		(layer "In2.Cu")
		(net "M_B_CPU0_SA_CS_N<0>")
	)
	(segment
		(start 331.563218 -257.182366)
		(end 331.184758 -257.182366)
		(width 0.18288)
		(layer "In2.Cu")
		(net "M_B_CPU0_SA_CS_N<0>")
	)
	(segment
		(start 296.455084 -268.298676)
		(end 296.28592 -268.46784)
		(width 0.18288)
		(layer "In2.Cu")
		(net "M_B_CPU0_SA_CS_N<0>")
	)
	(segment
		(start 287.924494 -268.298676)
		(end 287.792668 -268.298676)
		(width 0.18288)
		(layer "In2.Cu")
		(net "M_B_CPU0_SA_CS_N<0>")
	)
	(segment
		(start 291.969444 -268.298676)
		(end 289.044888 -268.298676)
		(width 0.18288)
		(layer "In2.Cu")
		(net "M_B_CPU0_SA_CS_N<0>")
	)
	(segment
		(start 311.920382 -265.688826)
		(end 309.78602 -266.572746)
		(width 0.18288)
		(layer "In2.Cu")
		(net "M_B_CPU0_SA_CS_N<0>")
	)
	(segment
		(start 288.277554 -269.01648)
		(end 288.084514 -268.82344)
		(width 0.18288)
		(layer "In2.Cu")
		(net "M_B_CPU0_SA_CS_N<0>")
	)
	(segment
		(start 294.643556 -268.291818)
		(end 294.379142 -268.556232)
		(width 0.18288)
		(layer "In2.Cu")
		(net "M_B_CPU0_SA_CS_N<0>")
	)
	(segment
		(start 293.277798 -268.556232)
		(end 292.893242 -268.171676)
		(width 0.18288)
		(layer "In2.Cu")
		(net "M_B_CPU0_SA_CS_N<0>")
	)
	(segment
		(start 292.893242 -268.171676)
		(end 292.096444 -268.171676)
		(width 0.18288)
		(layer "In2.Cu")
		(net "M_B_CPU0_SA_CS_N<0>")
	)
	(segment
		(start 294.379142 -268.556232)
		(end 293.277798 -268.556232)
		(width 0.18288)
		(layer "In2.Cu")
		(net "M_B_CPU0_SA_CS_N<0>")
	)
	(segment
		(start 300.059598 -269.14348)
		(end 299.214794 -268.298676)
		(width 0.18288)
		(layer "In2.Cu")
		(net "M_B_CPU0_SA_CS_N<0>")
	)
	(segment
		(start 303.530254 -268.266164)
		(end 302.652938 -269.14348)
		(width 0.18288)
		(layer "In2.Cu")
		(net "M_B_CPU0_SA_CS_N<0>")
	)
	(segment
		(start 287.792668 -268.298676)
		(end 287.360614 -267.866622)
		(width 0.18288)
		(layer "In2.Cu")
		(net "M_B_CPU0_SA_CS_N<0>")
	)
	(segment
		(start 323.158866 -260.273038)
		(end 317.10884 -262.779256)
		(width 0.18288)
		(layer "In2.Cu")
		(net "M_B_CPU0_SA_CS_N<0>")
	)
	(segment
		(start 295.621456 -268.46784)
		(end 295.445434 -268.291818)
		(width 0.18288)
		(layer "In2.Cu")
		(net "M_B_CPU0_SA_CS_N<0>")
	)
	(segment
		(start 303.530254 -268.070076)
		(end 303.530254 -268.266164)
		(width 0.18288)
		(layer "In2.Cu")
		(net "M_B_CPU0_SA_CS_N<0>")
	)
	(segment
		(start 324.080378 -259.351526)
		(end 323.158866 -260.273038)
		(width 0.18288)
		(layer "In2.Cu")
		(net "M_B_CPU0_SA_CS_N<0>")
	)
	(segment
		(start 332.209648 -257.550158)
		(end 331.841856 -257.182366)
		(width 0.088646)
		(layer "In2.Cu")
		(net "M_B_CPU0_SA_CS_N<0>")
	)
	(segment
		(start 336.4103 -257.483356)
		(end 336.38236 -257.499612)
		(width 0.088646)
		(layer "In2.Cu")
		(net "M_B_CPU0_SA_CS_N<0>")
	)
	(segment
		(start 288.884868 -268.458696)
		(end 288.884868 -268.82344)
		(width 0.18288)
		(layer "In2.Cu")
		(net "M_B_CPU0_SA_CS_N<0>")
	)
	(segment
		(start 317.10884 -262.779256)
		(end 314.19927 -265.688826)
		(width 0.18288)
		(layer "In2.Cu")
		(net "M_B_CPU0_SA_CS_N<0>")
	)
	(segment
		(start 289.044888 -268.298676)
		(end 288.884868 -268.458696)
		(width 0.18288)
		(layer "In2.Cu")
		(net "M_B_CPU0_SA_CS_N<0>")
	)
	(segment
		(start 288.084514 -268.458696)
		(end 287.924494 -268.298676)
		(width 0.18288)
		(layer "In2.Cu")
		(net "M_B_CPU0_SA_CS_N<0>")
	)
	(segment
		(start 329.015598 -259.351526)
		(end 324.080378 -259.351526)
		(width 0.18288)
		(layer "In2.Cu")
		(net "M_B_CPU0_SA_CS_N<0>")
	)
	(segment
		(start 314.19927 -265.688826)
		(end 311.920382 -265.688826)
		(width 0.18288)
		(layer "In2.Cu")
		(net "M_B_CPU0_SA_CS_N<0>")
	)
	(segment
		(start 306.71135 -267.411708)
		(end 304.188622 -267.411708)
		(width 0.18288)
		(layer "In2.Cu")
		(net "M_B_CPU0_SA_CS_N<0>")
	)
	(segment
		(start 288.691828 -269.01648)
		(end 288.277554 -269.01648)
		(width 0.18288)
		(layer "In2.Cu")
		(net "M_B_CPU0_SA_CS_N<0>")
	)
	(segment
		(start 331.841856 -257.182366)
		(end 331.563218 -257.182366)
		(width 0.088646)
		(layer "In2.Cu")
		(net "M_B_CPU0_SA_CS_N<0>")
	)
	(segment
		(start 299.214794 -268.298676)
		(end 296.455084 -268.298676)
		(width 0.18288)
		(layer "In2.Cu")
		(net "M_B_CPU0_SA_CS_N<0>")
	)
	(segment
		(start 295.445434 -268.291818)
		(end 294.643556 -268.291818)
		(width 0.18288)
		(layer "In2.Cu")
		(net "M_B_CPU0_SA_CS_N<0>")
	)
	(segment
		(start 309.78602 -266.572746)
		(end 307.550312 -266.572746)
		(width 0.18288)
		(layer "In2.Cu")
		(net "M_B_CPU0_SA_CS_N<0>")
	)
	(segment
		(start 292.096444 -268.171676)
		(end 291.969444 -268.298676)
		(width 0.18288)
		(layer "In2.Cu")
		(net "M_B_CPU0_SA_CS_N<0>")
	)
	(segment
		(start 296.28592 -268.46784)
		(end 295.621456 -268.46784)
		(width 0.18288)
		(layer "In2.Cu")
		(net "M_B_CPU0_SA_CS_N<0>")
	)
	(segment
		(start 337.134962 -257.175254)
		(end 336.4103 -257.483356)
		(width 0.088646)
		(layer "In2.Cu")
		(net "M_B_CPU0_SA_CS_N<0>")
	)
	(segment
		(start 288.884868 -268.82344)
		(end 288.691828 -269.01648)
		(width 0.18288)
		(layer "In2.Cu")
		(net "M_B_CPU0_SA_CS_N<0>")
	)
	(segment
		(start 304.188622 -267.411708)
		(end 303.530254 -268.070076)
		(width 0.18288)
		(layer "In2.Cu")
		(net "M_B_CPU0_SA_CS_N<0>")
	)
	(segment
		(start 331.184758 -257.182366)
		(end 329.015598 -259.351526)
		(width 0.18288)
		(layer "In2.Cu")
		(net "M_B_CPU0_SA_CS_N<0>")
	)
	(segment
		(start 332.435962 -257.550158)
		(end 332.209648 -257.550158)
		(width 0.088646)
		(layer "In2.Cu")
		(net "M_B_CPU0_SA_CS_N<0>")
	)
	(segment
		(start 307.550312 -266.572746)
		(end 306.71135 -267.411708)
		(width 0.18288)
		(layer "In2.Cu")
		(net "M_B_CPU0_SA_CS_N<0>")
	)
	(segment
		(start 302.652938 -269.14348)
		(end 300.059598 -269.14348)
		(width 0.18288)
		(layer "In2.Cu")
		(net "M_B_CPU0_SA_CS_N<0>")
	)
	(arc
		(start 334.128364 -257.499612)
		(mid 333.845662 -257.423836)
		(end 333.56296 -257.499612)
		(width 0.088646)
		(layer "In2.Cu")
		(net "M_B_CPU0_SA_CS_N<0>")
	)
	(arc
		(start 336.38236 -257.499612)
		(mid 336.195162 -257.549755)
		(end 336.007964 -257.499612)
		(width 0.088646)
		(layer "In2.Cu")
		(net "M_B_CPU0_SA_CS_N<0>")
	)
	(arc
		(start 335.44256 -257.499612)
		(mid 335.255362 -257.549755)
		(end 335.068164 -257.499612)
		(width 0.088646)
		(layer "In2.Cu")
		(net "M_B_CPU0_SA_CS_N<0>")
	)
	(arc
		(start 333.188564 -257.499612)
		(mid 332.905862 -257.423836)
		(end 332.62316 -257.499612)
		(width 0.088646)
		(layer "In2.Cu")
		(net "M_B_CPU0_SA_CS_N<0>")
	)
	(arc
		(start 333.56296 -257.499612)
		(mid 333.375762 -257.549755)
		(end 333.188564 -257.499612)
		(width 0.088646)
		(layer "In2.Cu")
		(net "M_B_CPU0_SA_CS_N<0>")
	)
	(arc
		(start 336.007964 -257.499612)
		(mid 335.725262 -257.423836)
		(end 335.44256 -257.499612)
		(width 0.088646)
		(layer "In2.Cu")
		(net "M_B_CPU0_SA_CS_N<0>")
	)
	(arc
		(start 332.62316 -257.499612)
		(mid 332.532888 -257.537211)
		(end 332.435962 -257.550158)
		(width 0.088646)
		(layer "In2.Cu")
		(net "M_B_CPU0_SA_CS_N<0>")
	)
	(arc
		(start 334.50276 -257.499612)
		(mid 334.315562 -257.549755)
		(end 334.128364 -257.499612)
		(width 0.088646)
		(layer "In2.Cu")
		(net "M_B_CPU0_SA_CS_N<0>")
	)
	(arc
		(start 335.068164 -257.499612)
		(mid 334.785462 -257.42387)
		(end 334.50276 -257.499612)
		(width 0.088646)
		(layer "In2.Cu")
		(net "M_B_CPU0_SA_CS_N<0>")
	)
	(segment
		(start 338.074762 -258.2672)
		(end 338.074762 -258.80314)
		(width 0.20066)
		(layer "F.Cu")
		(net "M_B_CPU0_SA_CB<7>")
	)
	(segment
		(start 295.544748 -270.841724)
		(end 295.000426 -270.841724)
		(width 0.20066)
		(layer "F.Cu")
		(net "M_B_CPU0_SA_CB<7>")
	)
	(segment
		(start 295.000426 -270.841724)
		(end 292.927532 -270.841724)
		(width 0.1016)
		(layer "F.Cu")
		(net "M_B_CPU0_SA_CB<7>")
	)
	(segment
		(start 292.927532 -270.841724)
		(end 292.689534 -270.841724)
		(width 0.101854)
		(layer "F.Cu")
		(net "M_B_CPU0_SA_CB<7>")
	)
	(segment
		(start 299.029882 -270.416782)
		(end 297.899582 -270.416782)
		(width 0.20066)
		(layer "F.Cu")
		(net "M_B_CPU0_SA_CB<7>")
	)
	(segment
		(start 292.178994 -270.542766)
		(end 292.05301 -270.416782)
		(width 0.20066)
		(layer "F.Cu")
		(net "M_B_CPU0_SA_CB<7>")
	)
	(segment
		(start 295.82237 -270.412464)
		(end 295.693846 -270.540988)
		(width 0.20066)
		(layer "F.Cu")
		(net "M_B_CPU0_SA_CB<7>")
	)
	(segment
		(start 292.689534 -270.841724)
		(end 292.67531 -270.855948)
		(width 0.101854)
		(layer "F.Cu")
		(net "M_B_CPU0_SA_CB<7>")
	)
	(segment
		(start 295.693846 -270.692626)
		(end 295.544748 -270.841724)
		(width 0.20066)
		(layer "F.Cu")
		(net "M_B_CPU0_SA_CB<7>")
	)
	(segment
		(start 296.875962 -270.6243)
		(end 296.42943 -270.6243)
		(width 0.20066)
		(layer "F.Cu")
		(net "M_B_CPU0_SA_CB<7>")
	)
	(segment
		(start 292.05301 -270.416782)
		(end 290.355782 -270.416782)
		(width 0.20066)
		(layer "F.Cu")
		(net "M_B_CPU0_SA_CB<7>")
	)
	(segment
		(start 292.67531 -270.855948)
		(end 292.321488 -270.855948)
		(width 0.20066)
		(layer "F.Cu")
		(net "M_B_CPU0_SA_CB<7>")
	)
	(segment
		(start 295.693846 -270.540988)
		(end 295.693846 -270.692626)
		(width 0.20066)
		(layer "F.Cu")
		(net "M_B_CPU0_SA_CB<7>")
	)
	(segment
		(start 296.42943 -270.6243)
		(end 296.217594 -270.412464)
		(width 0.20066)
		(layer "F.Cu")
		(net "M_B_CPU0_SA_CB<7>")
	)
	(segment
		(start 297.899582 -270.416782)
		(end 297.08348 -270.416782)
		(width 0.20066)
		(layer "F.Cu")
		(net "M_B_CPU0_SA_CB<7>")
	)
	(segment
		(start 296.217594 -270.412464)
		(end 295.82237 -270.412464)
		(width 0.20066)
		(layer "F.Cu")
		(net "M_B_CPU0_SA_CB<7>")
	)
	(segment
		(start 292.178994 -270.713454)
		(end 292.178994 -270.542766)
		(width 0.20066)
		(layer "F.Cu")
		(net "M_B_CPU0_SA_CB<7>")
	)
	(segment
		(start 297.08348 -270.416782)
		(end 296.875962 -270.6243)
		(width 0.20066)
		(layer "F.Cu")
		(net "M_B_CPU0_SA_CB<7>")
	)
	(segment
		(start 292.321488 -270.855948)
		(end 292.178994 -270.713454)
		(width 0.20066)
		(layer "F.Cu")
		(net "M_B_CPU0_SA_CB<7>")
	)
	(segment
		(start 307.022246 -269.794228)
		(end 306.82311 -269.993364)
		(width 0.18288)
		(layer "In2.Cu")
		(net "M_B_CPU0_SA_CB<7>")
	)
	(segment
		(start 305.027584 -269.800324)
		(end 304.834544 -269.993364)
		(width 0.18288)
		(layer "In2.Cu")
		(net "M_B_CPU0_SA_CB<7>")
	)
	(segment
		(start 312.178446 -268.309852)
		(end 311.862216 -268.440916)
		(width 0.18288)
		(layer "In2.Cu")
		(net "M_B_CPU0_SA_CB<7>")
	)
	(segment
		(start 310.566816 -269.141702)
		(end 309.4101 -269.141702)
		(width 0.18288)
		(layer "In2.Cu")
		(net "M_B_CPU0_SA_CB<7>")
	)
	(segment
		(start 316.860174 -265.671554)
		(end 316.860174 -265.94435)
		(width 0.18288)
		(layer "In2.Cu")
		(net "M_B_CPU0_SA_CB<7>")
	)
	(segment
		(start 314.93206 -267.295884)
		(end 314.691776 -267.536168)
		(width 0.18288)
		(layer "In2.Cu")
		(net "M_B_CPU0_SA_CB<7>")
	)
	(segment
		(start 323.879464 -261.622032)
		(end 319.274952 -263.529572)
		(width 0.18288)
		(layer "In2.Cu")
		(net "M_B_CPU0_SA_CB<7>")
	)
	(segment
		(start 312.19648 -268.291818)
		(end 312.178446 -268.309852)
		(width 0.18288)
		(layer "In2.Cu")
		(net "M_B_CPU0_SA_CB<7>")
	)
	(segment
		(start 332.4352 -258.237736)
		(end 332.16977 -258.237736)
		(width 0.088646)
		(layer "In2.Cu")
		(net "M_B_CPU0_SA_CB<7>")
	)
	(segment
		(start 317.227458 -265.043666)
		(end 316.954662 -265.043666)
		(width 0.18288)
		(layer "In2.Cu")
		(net "M_B_CPU0_SA_CB<7>")
	)
	(segment
		(start 306.82311 -269.993364)
		(end 305.924204 -269.993364)
		(width 0.18288)
		(layer "In2.Cu")
		(net "M_B_CPU0_SA_CB<7>")
	)
	(segment
		(start 319.274952 -263.529572)
		(end 318.625728 -264.178796)
		(width 0.18288)
		(layer "In2.Cu")
		(net "M_B_CPU0_SA_CB<7>")
	)
	(segment
		(start 309.4101 -269.141702)
		(end 309.21706 -268.948662)
		(width 0.18288)
		(layer "In2.Cu")
		(net "M_B_CPU0_SA_CB<7>")
	)
	(segment
		(start 316.232286 -266.038838)
		(end 315.95949 -266.038838)
		(width 0.18288)
		(layer "In2.Cu")
		(net "M_B_CPU0_SA_CB<7>")
	)
	(segment
		(start 315.865002 -266.666726)
		(end 315.865002 -266.939522)
		(width 0.18288)
		(layer "In2.Cu")
		(net "M_B_CPU0_SA_CB<7>")
	)
	(segment
		(start 329.490324 -260.652006)
		(end 324.84949 -260.652006)
		(width 0.18288)
		(layer "In2.Cu")
		(net "M_B_CPU0_SA_CB<7>")
	)
	(segment
		(start 309.02402 -268.2748)
		(end 308.71414 -268.2748)
		(width 0.18288)
		(layer "In2.Cu")
		(net "M_B_CPU0_SA_CB<7>")
	)
	(segment
		(start 324.84949 -260.652006)
		(end 323.879464 -261.622032)
		(width 0.18288)
		(layer "In2.Cu")
		(net "M_B_CPU0_SA_CB<7>")
	)
	(segment
		(start 316.954662 -265.043666)
		(end 316.729872 -265.268456)
		(width 0.18288)
		(layer "In2.Cu")
		(net "M_B_CPU0_SA_CB<7>")
	)
	(segment
		(start 317.855346 -264.676382)
		(end 317.855346 -264.949178)
		(width 0.18288)
		(layer "In2.Cu")
		(net "M_B_CPU0_SA_CB<7>")
	)
	(segment
		(start 315.7347 -266.536424)
		(end 315.865002 -266.666726)
		(width 0.18288)
		(layer "In2.Cu")
		(net "M_B_CPU0_SA_CB<7>")
	)
	(segment
		(start 308.034436 -269.141702)
		(end 307.970428 -269.20571)
		(width 0.18288)
		(layer "In2.Cu")
		(net "M_B_CPU0_SA_CB<7>")
	)
	(segment
		(start 315.865002 -266.939522)
		(end 315.50864 -267.295884)
		(width 0.18288)
		(layer "In2.Cu")
		(net "M_B_CPU0_SA_CB<7>")
	)
	(segment
		(start 317.35776 -265.173968)
		(end 317.227458 -265.043666)
		(width 0.18288)
		(layer "In2.Cu")
		(net "M_B_CPU0_SA_CB<7>")
	)
	(segment
		(start 303.67478 -270.53032)
		(end 303.309274 -270.895826)
		(width 0.18288)
		(layer "In2.Cu")
		(net "M_B_CPU0_SA_CB<7>")
	)
	(segment
		(start 317.725044 -264.54608)
		(end 317.855346 -264.676382)
		(width 0.18288)
		(layer "In2.Cu")
		(net "M_B_CPU0_SA_CB<7>")
	)
	(segment
		(start 314.691776 -267.536168)
		(end 314.691776 -268.040866)
		(width 0.18288)
		(layer "In2.Cu")
		(net "M_B_CPU0_SA_CB<7>")
	)
	(segment
		(start 305.731164 -269.45844)
		(end 305.538124 -269.2654)
		(width 0.18288)
		(layer "In2.Cu")
		(net "M_B_CPU0_SA_CB<7>")
	)
	(segment
		(start 311.01792 -268.745716)
		(end 310.913526 -268.998192)
		(width 0.18288)
		(layer "In2.Cu")
		(net "M_B_CPU0_SA_CB<7>")
	)
	(segment
		(start 317.630556 -265.173968)
		(end 317.35776 -265.173968)
		(width 0.18288)
		(layer "In2.Cu")
		(net "M_B_CPU0_SA_CB<7>")
	)
	(segment
		(start 308.51348 -268.948662)
		(end 308.32044 -269.141702)
		(width 0.18288)
		(layer "In2.Cu")
		(net "M_B_CPU0_SA_CB<7>")
	)
	(segment
		(start 305.027584 -269.45844)
		(end 305.027584 -269.800324)
		(width 0.18288)
		(layer "In2.Cu")
		(net "M_B_CPU0_SA_CB<7>")
	)
	(segment
		(start 308.51348 -268.47546)
		(end 308.51348 -268.948662)
		(width 0.18288)
		(layer "In2.Cu")
		(net "M_B_CPU0_SA_CB<7>")
	)
	(segment
		(start 310.94807 -268.072616)
		(end 310.843422 -268.324838)
		(width 0.18288)
		(layer "In2.Cu")
		(net "M_B_CPU0_SA_CB<7>")
	)
	(segment
		(start 307.970428 -269.20571)
		(end 307.215286 -269.20571)
		(width 0.18288)
		(layer "In2.Cu")
		(net "M_B_CPU0_SA_CB<7>")
	)
	(segment
		(start 316.860174 -265.94435)
		(end 316.635384 -266.16914)
		(width 0.18288)
		(layer "In2.Cu")
		(net "M_B_CPU0_SA_CB<7>")
	)
	(segment
		(start 315.50864 -267.295884)
		(end 314.93206 -267.295884)
		(width 0.18288)
		(layer "In2.Cu")
		(net "M_B_CPU0_SA_CB<7>")
	)
	(segment
		(start 317.725044 -264.273284)
		(end 317.725044 -264.54608)
		(width 0.18288)
		(layer "In2.Cu")
		(net "M_B_CPU0_SA_CB<7>")
	)
	(segment
		(start 338.074762 -258.80314)
		(end 337.761834 -258.80314)
		(width 0.088646)
		(layer "In2.Cu")
		(net "M_B_CPU0_SA_CB<7>")
	)
	(segment
		(start 331.873352 -258.534154)
		(end 331.764894 -258.534154)
		(width 0.088646)
		(layer "In2.Cu")
		(net "M_B_CPU0_SA_CB<7>")
	)
	(segment
		(start 305.924204 -269.993364)
		(end 305.731164 -269.800324)
		(width 0.18288)
		(layer "In2.Cu")
		(net "M_B_CPU0_SA_CB<7>")
	)
	(segment
		(start 312.591958 -267.63726)
		(end 312.591958 -268.098778)
		(width 0.18288)
		(layer "In2.Cu")
		(net "M_B_CPU0_SA_CB<7>")
	)
	(segment
		(start 316.362588 -266.16914)
		(end 316.232286 -266.038838)
		(width 0.18288)
		(layer "In2.Cu")
		(net "M_B_CPU0_SA_CB<7>")
	)
	(segment
		(start 313.295538 -267.6398)
		(end 313.099958 -267.44422)
		(width 0.18288)
		(layer "In2.Cu")
		(net "M_B_CPU0_SA_CB<7>")
	)
	(segment
		(start 308.71414 -268.2748)
		(end 308.51348 -268.47546)
		(width 0.18288)
		(layer "In2.Cu")
		(net "M_B_CPU0_SA_CB<7>")
	)
	(segment
		(start 311.241948 -267.950696)
		(end 310.94807 -268.072616)
		(width 0.18288)
		(layer "In2.Cu")
		(net "M_B_CPU0_SA_CB<7>")
	)
	(segment
		(start 307.215286 -269.20571)
		(end 307.022246 -269.39875)
		(width 0.18288)
		(layer "In2.Cu")
		(net "M_B_CPU0_SA_CB<7>")
	)
	(segment
		(start 303.944528 -269.993364)
		(end 303.67478 -270.263112)
		(width 0.18288)
		(layer "In2.Cu")
		(net "M_B_CPU0_SA_CB<7>")
	)
	(segment
		(start 300.459394 -270.895826)
		(end 300.208188 -271.147032)
		(width 0.18288)
		(layer "In2.Cu")
		(net "M_B_CPU0_SA_CB<7>")
	)
	(segment
		(start 318.22263 -264.048494)
		(end 317.949834 -264.048494)
		(width 0.18288)
		(layer "In2.Cu")
		(net "M_B_CPU0_SA_CB<7>")
	)
	(segment
		(start 305.731164 -269.800324)
		(end 305.731164 -269.45844)
		(width 0.18288)
		(layer "In2.Cu")
		(net "M_B_CPU0_SA_CB<7>")
	)
	(segment
		(start 311.493662 -268.055344)
		(end 311.241948 -267.950696)
		(width 0.18288)
		(layer "In2.Cu")
		(net "M_B_CPU0_SA_CB<7>")
	)
	(segment
		(start 314.440824 -268.291818)
		(end 313.488578 -268.291818)
		(width 0.18288)
		(layer "In2.Cu")
		(net "M_B_CPU0_SA_CB<7>")
	)
	(segment
		(start 313.295538 -268.098778)
		(end 313.295538 -267.6398)
		(width 0.18288)
		(layer "In2.Cu")
		(net "M_B_CPU0_SA_CB<7>")
	)
	(segment
		(start 317.855346 -264.949178)
		(end 317.630556 -265.173968)
		(width 0.18288)
		(layer "In2.Cu")
		(net "M_B_CPU0_SA_CB<7>")
	)
	(segment
		(start 303.309274 -270.895826)
		(end 300.459394 -270.895826)
		(width 0.18288)
		(layer "In2.Cu")
		(net "M_B_CPU0_SA_CB<7>")
	)
	(segment
		(start 309.21706 -268.948662)
		(end 309.21706 -268.46784)
		(width 0.18288)
		(layer "In2.Cu")
		(net "M_B_CPU0_SA_CB<7>")
	)
	(segment
		(start 313.488578 -268.291818)
		(end 313.295538 -268.098778)
		(width 0.18288)
		(layer "In2.Cu")
		(net "M_B_CPU0_SA_CB<7>")
	)
	(segment
		(start 318.625728 -264.178796)
		(end 318.352932 -264.178796)
		(width 0.18288)
		(layer "In2.Cu")
		(net "M_B_CPU0_SA_CB<7>")
	)
	(segment
		(start 329.647042 -260.652006)
		(end 329.490324 -260.652006)
		(width 0.088646)
		(layer "In2.Cu")
		(net "M_B_CPU0_SA_CB<7>")
	)
	(segment
		(start 316.729872 -265.268456)
		(end 316.729872 -265.541252)
		(width 0.18288)
		(layer "In2.Cu")
		(net "M_B_CPU0_SA_CB<7>")
	)
	(segment
		(start 305.220624 -269.2654)
		(end 305.027584 -269.45844)
		(width 0.18288)
		(layer "In2.Cu")
		(net "M_B_CPU0_SA_CB<7>")
	)
	(segment
		(start 318.352932 -264.178796)
		(end 318.22263 -264.048494)
		(width 0.18288)
		(layer "In2.Cu")
		(net "M_B_CPU0_SA_CB<7>")
	)
	(segment
		(start 332.16977 -258.237736)
		(end 331.873352 -258.534154)
		(width 0.088646)
		(layer "In2.Cu")
		(net "M_B_CPU0_SA_CB<7>")
	)
	(segment
		(start 337.761834 -258.80314)
		(end 337.69681 -258.738116)
		(width 0.088646)
		(layer "In2.Cu")
		(net "M_B_CPU0_SA_CB<7>")
	)
	(segment
		(start 316.635384 -266.16914)
		(end 316.362588 -266.16914)
		(width 0.18288)
		(layer "In2.Cu")
		(net "M_B_CPU0_SA_CB<7>")
	)
	(segment
		(start 300.208188 -271.147032)
		(end 299.760132 -271.147032)
		(width 0.18288)
		(layer "In2.Cu")
		(net "M_B_CPU0_SA_CB<7>")
	)
	(segment
		(start 311.862216 -268.440916)
		(end 311.610248 -268.336268)
		(width 0.18288)
		(layer "In2.Cu")
		(net "M_B_CPU0_SA_CB<7>")
	)
	(segment
		(start 303.67478 -270.263112)
		(end 303.67478 -270.53032)
		(width 0.18288)
		(layer "In2.Cu")
		(net "M_B_CPU0_SA_CB<7>")
	)
	(segment
		(start 311.610248 -268.336268)
		(end 311.493662 -268.055344)
		(width 0.18288)
		(layer "In2.Cu")
		(net "M_B_CPU0_SA_CB<7>")
	)
	(segment
		(start 312.398918 -268.291818)
		(end 312.19648 -268.291818)
		(width 0.18288)
		(layer "In2.Cu")
		(net "M_B_CPU0_SA_CB<7>")
	)
	(segment
		(start 316.729872 -265.541252)
		(end 316.860174 -265.671554)
		(width 0.18288)
		(layer "In2.Cu")
		(net "M_B_CPU0_SA_CB<7>")
	)
	(segment
		(start 315.7347 -266.263628)
		(end 315.7347 -266.536424)
		(width 0.18288)
		(layer "In2.Cu")
		(net "M_B_CPU0_SA_CB<7>")
	)
	(segment
		(start 313.099958 -267.44422)
		(end 312.784998 -267.44422)
		(width 0.18288)
		(layer "In2.Cu")
		(net "M_B_CPU0_SA_CB<7>")
	)
	(segment
		(start 317.949834 -264.048494)
		(end 317.725044 -264.273284)
		(width 0.18288)
		(layer "In2.Cu")
		(net "M_B_CPU0_SA_CB<7>")
	)
	(segment
		(start 310.843422 -268.324838)
		(end 311.01792 -268.745716)
		(width 0.18288)
		(layer "In2.Cu")
		(net "M_B_CPU0_SA_CB<7>")
	)
	(segment
		(start 314.691776 -268.040866)
		(end 314.440824 -268.291818)
		(width 0.18288)
		(layer "In2.Cu")
		(net "M_B_CPU0_SA_CB<7>")
	)
	(segment
		(start 307.022246 -269.39875)
		(end 307.022246 -269.794228)
		(width 0.18288)
		(layer "In2.Cu")
		(net "M_B_CPU0_SA_CB<7>")
	)
	(segment
		(start 315.95949 -266.038838)
		(end 315.7347 -266.263628)
		(width 0.18288)
		(layer "In2.Cu")
		(net "M_B_CPU0_SA_CB<7>")
	)
	(segment
		(start 331.764894 -258.534154)
		(end 329.647042 -260.652006)
		(width 0.088646)
		(layer "In2.Cu")
		(net "M_B_CPU0_SA_CB<7>")
	)
	(segment
		(start 299.760132 -271.147032)
		(end 299.029882 -270.416782)
		(width 0.18288)
		(layer "In2.Cu")
		(net "M_B_CPU0_SA_CB<7>")
	)
	(segment
		(start 312.591958 -268.098778)
		(end 312.398918 -268.291818)
		(width 0.18288)
		(layer "In2.Cu")
		(net "M_B_CPU0_SA_CB<7>")
	)
	(segment
		(start 308.32044 -269.141702)
		(end 308.034436 -269.141702)
		(width 0.18288)
		(layer "In2.Cu")
		(net "M_B_CPU0_SA_CB<7>")
	)
	(segment
		(start 310.913526 -268.998192)
		(end 310.566816 -269.141702)
		(width 0.18288)
		(layer "In2.Cu")
		(net "M_B_CPU0_SA_CB<7>")
	)
	(segment
		(start 305.538124 -269.2654)
		(end 305.220624 -269.2654)
		(width 0.18288)
		(layer "In2.Cu")
		(net "M_B_CPU0_SA_CB<7>")
	)
	(segment
		(start 304.834544 -269.993364)
		(end 303.944528 -269.993364)
		(width 0.18288)
		(layer "In2.Cu")
		(net "M_B_CPU0_SA_CB<7>")
	)
	(segment
		(start 309.21706 -268.46784)
		(end 309.02402 -268.2748)
		(width 0.18288)
		(layer "In2.Cu")
		(net "M_B_CPU0_SA_CB<7>")
	)
	(segment
		(start 312.784998 -267.44422)
		(end 312.591958 -267.63726)
		(width 0.18288)
		(layer "In2.Cu")
		(net "M_B_CPU0_SA_CB<7>")
	)
	(arc
		(start 332.718664 -258.313428)
		(mid 332.58193 -258.256851)
		(end 332.4352 -258.237736)
		(width 0.088646)
		(layer "In2.Cu")
		(net "M_B_CPU0_SA_CB<7>")
	)
	(arc
		(start 334.598264 -258.313428)
		(mid 334.315562 -258.237686)
		(end 334.03286 -258.313428)
		(width 0.088646)
		(layer "In2.Cu")
		(net "M_B_CPU0_SA_CB<7>")
	)
	(arc
		(start 334.03286 -258.313428)
		(mid 333.845662 -258.363571)
		(end 333.658464 -258.313428)
		(width 0.088646)
		(layer "In2.Cu")
		(net "M_B_CPU0_SA_CB<7>")
	)
	(arc
		(start 335.538064 -258.313428)
		(mid 335.255362 -258.237686)
		(end 334.97266 -258.313428)
		(width 0.088646)
		(layer "In2.Cu")
		(net "M_B_CPU0_SA_CB<7>")
	)
	(arc
		(start 336.85226 -258.313428)
		(mid 336.665062 -258.363571)
		(end 336.477864 -258.313428)
		(width 0.088646)
		(layer "In2.Cu")
		(net "M_B_CPU0_SA_CB<7>")
	)
	(arc
		(start 337.69681 -258.738116)
		(mid 337.607656 -258.492629)
		(end 337.417664 -258.313428)
		(width 0.088646)
		(layer "In2.Cu")
		(net "M_B_CPU0_SA_CB<7>")
	)
	(arc
		(start 333.09306 -258.313428)
		(mid 332.905862 -258.363571)
		(end 332.718664 -258.313428)
		(width 0.088646)
		(layer "In2.Cu")
		(net "M_B_CPU0_SA_CB<7>")
	)
	(arc
		(start 336.477864 -258.313428)
		(mid 336.195162 -258.237686)
		(end 335.91246 -258.313428)
		(width 0.088646)
		(layer "In2.Cu")
		(net "M_B_CPU0_SA_CB<7>")
	)
	(arc
		(start 337.417664 -258.313428)
		(mid 337.134962 -258.237686)
		(end 336.85226 -258.313428)
		(width 0.088646)
		(layer "In2.Cu")
		(net "M_B_CPU0_SA_CB<7>")
	)
	(arc
		(start 333.658464 -258.313428)
		(mid 333.375762 -258.237686)
		(end 333.09306 -258.313428)
		(width 0.088646)
		(layer "In2.Cu")
		(net "M_B_CPU0_SA_CB<7>")
	)
	(arc
		(start 334.97266 -258.313428)
		(mid 334.785462 -258.363571)
		(end 334.598264 -258.313428)
		(width 0.088646)
		(layer "In2.Cu")
		(net "M_B_CPU0_SA_CB<7>")
	)
	(arc
		(start 335.91246 -258.313428)
		(mid 335.725262 -258.363571)
		(end 335.538064 -258.313428)
		(width 0.088646)
		(layer "In2.Cu")
		(net "M_B_CPU0_SA_CB<7>")
	)
	(segment
		(start 338.544662 -259.08127)
		(end 338.544662 -259.616956)
		(width 0.20066)
		(layer "F.Cu")
		(net "M_B_CPU0_SA_CB<6>")
	)
	(segment
		(start 292.67531 -271.681702)
		(end 291.937948 -271.681702)
		(width 0.20066)
		(layer "F.Cu")
		(net "M_B_CPU0_SA_CB<6>")
	)
	(segment
		(start 295.000426 -271.691862)
		(end 292.940486 -271.691862)
		(width 0.1016)
		(layer "F.Cu")
		(net "M_B_CPU0_SA_CB<6>")
	)
	(segment
		(start 291.502846 -272.116804)
		(end 290.355782 -272.116804)
		(width 0.20066)
		(layer "F.Cu")
		(net "M_B_CPU0_SA_CB<6>")
	)
	(segment
		(start 295.944544 -272.32864)
		(end 295.777158 -272.161254)
		(width 0.20066)
		(layer "F.Cu")
		(net "M_B_CPU0_SA_CB<6>")
	)
	(segment
		(start 291.937948 -271.681702)
		(end 291.502846 -272.116804)
		(width 0.20066)
		(layer "F.Cu")
		(net "M_B_CPU0_SA_CB<6>")
	)
	(segment
		(start 295.777158 -272.161254)
		(end 295.777158 -271.835626)
		(width 0.20066)
		(layer "F.Cu")
		(net "M_B_CPU0_SA_CB<6>")
	)
	(segment
		(start 295.777158 -271.835626)
		(end 295.633394 -271.691862)
		(width 0.20066)
		(layer "F.Cu")
		(net "M_B_CPU0_SA_CB<6>")
	)
	(segment
		(start 295.633394 -271.691862)
		(end 295.000426 -271.691862)
		(width 0.20066)
		(layer "F.Cu")
		(net "M_B_CPU0_SA_CB<6>")
	)
	(segment
		(start 296.584878 -272.116804)
		(end 296.373042 -272.32864)
		(width 0.20066)
		(layer "F.Cu")
		(net "M_B_CPU0_SA_CB<6>")
	)
	(segment
		(start 338.544916 -259.081016)
		(end 338.544662 -259.08127)
		(width 0.20066)
		(layer "F.Cu")
		(net "M_B_CPU0_SA_CB<6>")
	)
	(segment
		(start 292.68547 -271.691862)
		(end 292.67531 -271.681702)
		(width 0.101854)
		(layer "F.Cu")
		(net "M_B_CPU0_SA_CB<6>")
	)
	(segment
		(start 292.940486 -271.691862)
		(end 292.68547 -271.691862)
		(width 0.101854)
		(layer "F.Cu")
		(net "M_B_CPU0_SA_CB<6>")
	)
	(segment
		(start 297.899582 -272.116804)
		(end 296.584878 -272.116804)
		(width 0.20066)
		(layer "F.Cu")
		(net "M_B_CPU0_SA_CB<6>")
	)
	(segment
		(start 299.029882 -272.116804)
		(end 297.899582 -272.116804)
		(width 0.20066)
		(layer "F.Cu")
		(net "M_B_CPU0_SA_CB<6>")
	)
	(segment
		(start 296.373042 -272.32864)
		(end 295.944544 -272.32864)
		(width 0.20066)
		(layer "F.Cu")
		(net "M_B_CPU0_SA_CB<6>")
	)
	(segment
		(start 319.057274 -265.475212)
		(end 319.180464 -265.598402)
		(width 0.18288)
		(layer "In2.Cu")
		(net "M_B_CPU0_SA_CB<6>")
	)
	(segment
		(start 319.55486 -264.977626)
		(end 319.282064 -264.977626)
		(width 0.18288)
		(layer "In2.Cu")
		(net "M_B_CPU0_SA_CB<6>")
	)
	(segment
		(start 319.057274 -265.202416)
		(end 319.057274 -265.475212)
		(width 0.18288)
		(layer "In2.Cu")
		(net "M_B_CPU0_SA_CB<6>")
	)
	(segment
		(start 310.43372 -271.14627)
		(end 309.972964 -271.14627)
		(width 0.18288)
		(layer "In2.Cu")
		(net "M_B_CPU0_SA_CB<6>")
	)
	(segment
		(start 320.175636 -264.477246)
		(end 320.175636 -264.876026)
		(width 0.18288)
		(layer "In2.Cu")
		(net "M_B_CPU0_SA_CB<6>")
	)
	(segment
		(start 306.493672 -271.943576)
		(end 305.859942 -271.309846)
		(width 0.18288)
		(layer "In2.Cu")
		(net "M_B_CPU0_SA_CB<6>")
	)
	(segment
		(start 316.071758 -268.460728)
		(end 316.194948 -268.583918)
		(width 0.18288)
		(layer "In2.Cu")
		(net "M_B_CPU0_SA_CB<6>")
	)
	(segment
		(start 313.78906 -270.013176)
		(end 311.566814 -270.013176)
		(width 0.18288)
		(layer "In2.Cu")
		(net "M_B_CPU0_SA_CB<6>")
	)
	(segment
		(start 319.180464 -265.598402)
		(end 319.180464 -265.871198)
		(width 0.18288)
		(layer "In2.Cu")
		(net "M_B_CPU0_SA_CB<6>")
	)
	(segment
		(start 307.011832 -271.943576)
		(end 306.493672 -271.943576)
		(width 0.18288)
		(layer "In2.Cu")
		(net "M_B_CPU0_SA_CB<6>")
	)
	(segment
		(start 314.065666 -270.289782)
		(end 313.78906 -270.013176)
		(width 0.18288)
		(layer "In2.Cu")
		(net "M_B_CPU0_SA_CB<6>")
	)
	(segment
		(start 318.062102 -266.197588)
		(end 318.062102 -266.470384)
		(width 0.18288)
		(layer "In2.Cu")
		(net "M_B_CPU0_SA_CB<6>")
	)
	(segment
		(start 316.071758 -268.187932)
		(end 316.071758 -268.460728)
		(width 0.18288)
		(layer "In2.Cu")
		(net "M_B_CPU0_SA_CB<6>")
	)
	(segment
		(start 315.697362 -269.081504)
		(end 315.574172 -268.958314)
		(width 0.18288)
		(layer "In2.Cu")
		(net "M_B_CPU0_SA_CB<6>")
	)
	(segment
		(start 317.19012 -267.588746)
		(end 317.19012 -267.861542)
		(width 0.18288)
		(layer "In2.Cu")
		(net "M_B_CPU0_SA_CB<6>")
	)
	(segment
		(start 309.701946 -270.875252)
		(end 307.477668 -270.875252)
		(width 0.18288)
		(layer "In2.Cu")
		(net "M_B_CPU0_SA_CB<6>")
	)
	(segment
		(start 316.692534 -268.086332)
		(end 316.569344 -267.963142)
		(width 0.18288)
		(layer "In2.Cu")
		(net "M_B_CPU0_SA_CB<6>")
	)
	(segment
		(start 324.455028 -262.483854)
		(end 321.230498 -263.821164)
		(width 0.18288)
		(layer "In2.Cu")
		(net "M_B_CPU0_SA_CB<6>")
	)
	(segment
		(start 300.218348 -272.83029)
		(end 299.693076 -272.83029)
		(width 0.18288)
		(layer "In2.Cu")
		(net "M_B_CPU0_SA_CB<6>")
	)
	(segment
		(start 315.199776 -269.851886)
		(end 314.76188 -270.289782)
		(width 0.18288)
		(layer "In2.Cu")
		(net "M_B_CPU0_SA_CB<6>")
	)
	(segment
		(start 301.755048 -272.17497)
		(end 300.873668 -272.17497)
		(width 0.18288)
		(layer "In2.Cu")
		(net "M_B_CPU0_SA_CB<6>")
	)
	(segment
		(start 329.490324 -261.342886)
		(end 325.595996 -261.342886)
		(width 0.18288)
		(layer "In2.Cu")
		(net "M_B_CPU0_SA_CB<6>")
	)
	(segment
		(start 316.194948 -268.583918)
		(end 316.194948 -268.856714)
		(width 0.18288)
		(layer "In2.Cu")
		(net "M_B_CPU0_SA_CB<6>")
	)
	(segment
		(start 338.231988 -259.61721)
		(end 338.166456 -259.551678)
		(width 0.088646)
		(layer "In2.Cu")
		(net "M_B_CPU0_SA_CB<6>")
	)
	(segment
		(start 305.859942 -271.309846)
		(end 304.988468 -271.309846)
		(width 0.18288)
		(layer "In2.Cu")
		(net "M_B_CPU0_SA_CB<6>")
	)
	(segment
		(start 321.230498 -263.821164)
		(end 320.946018 -264.105644)
		(width 0.18288)
		(layer "In2.Cu")
		(net "M_B_CPU0_SA_CB<6>")
	)
	(segment
		(start 317.960502 -267.09116)
		(end 317.687706 -267.09116)
		(width 0.18288)
		(layer "In2.Cu")
		(net "M_B_CPU0_SA_CB<6>")
	)
	(segment
		(start 318.955674 -266.095988)
		(end 318.682878 -266.095988)
		(width 0.18288)
		(layer "In2.Cu")
		(net "M_B_CPU0_SA_CB<6>")
	)
	(segment
		(start 317.06693 -267.465556)
		(end 317.19012 -267.588746)
		(width 0.18288)
		(layer "In2.Cu")
		(net "M_B_CPU0_SA_CB<6>")
	)
	(segment
		(start 315.076586 -269.4559)
		(end 315.199776 -269.57909)
		(width 0.18288)
		(layer "In2.Cu")
		(net "M_B_CPU0_SA_CB<6>")
	)
	(segment
		(start 316.96533 -268.086332)
		(end 316.692534 -268.086332)
		(width 0.18288)
		(layer "In2.Cu")
		(net "M_B_CPU0_SA_CB<6>")
	)
	(segment
		(start 325.595996 -261.342886)
		(end 324.455028 -262.483854)
		(width 0.18288)
		(layer "In2.Cu")
		(net "M_B_CPU0_SA_CB<6>")
	)
	(segment
		(start 299.693076 -272.83029)
		(end 299.029882 -272.167096)
		(width 0.18288)
		(layer "In2.Cu")
		(net "M_B_CPU0_SA_CB<6>")
	)
	(segment
		(start 311.566814 -270.013176)
		(end 311.2897 -270.29029)
		(width 0.18288)
		(layer "In2.Cu")
		(net "M_B_CPU0_SA_CB<6>")
	)
	(segment
		(start 318.286892 -265.972798)
		(end 318.062102 -266.197588)
		(width 0.18288)
		(layer "In2.Cu")
		(net "M_B_CPU0_SA_CB<6>")
	)
	(segment
		(start 309.972964 -271.14627)
		(end 309.701946 -270.875252)
		(width 0.18288)
		(layer "In2.Cu")
		(net "M_B_CPU0_SA_CB<6>")
	)
	(segment
		(start 299.029882 -272.167096)
		(end 299.029882 -272.116804)
		(width 0.18288)
		(layer "In2.Cu")
		(net "M_B_CPU0_SA_CB<6>")
	)
	(segment
		(start 303.06518 -272.624042)
		(end 302.902366 -272.786856)
		(width 0.18288)
		(layer "In2.Cu")
		(net "M_B_CPU0_SA_CB<6>")
	)
	(segment
		(start 302.902366 -272.786856)
		(end 302.366934 -272.786856)
		(width 0.18288)
		(layer "In2.Cu")
		(net "M_B_CPU0_SA_CB<6>")
	)
	(segment
		(start 317.19012 -267.861542)
		(end 316.96533 -268.086332)
		(width 0.18288)
		(layer "In2.Cu")
		(net "M_B_CPU0_SA_CB<6>")
	)
	(segment
		(start 319.950846 -265.100816)
		(end 319.67805 -265.100816)
		(width 0.18288)
		(layer "In2.Cu")
		(net "M_B_CPU0_SA_CB<6>")
	)
	(segment
		(start 319.67805 -265.100816)
		(end 319.55486 -264.977626)
		(width 0.18288)
		(layer "In2.Cu")
		(net "M_B_CPU0_SA_CB<6>")
	)
	(segment
		(start 336.024982 -259.13715)
		(end 336.007964 -259.127498)
		(width 0.088646)
		(layer "In2.Cu")
		(net "M_B_CPU0_SA_CB<6>")
	)
	(segment
		(start 314.76188 -270.289782)
		(end 314.065666 -270.289782)
		(width 0.18288)
		(layer "In2.Cu")
		(net "M_B_CPU0_SA_CB<6>")
	)
	(segment
		(start 318.185292 -266.593574)
		(end 318.185292 -266.86637)
		(width 0.18288)
		(layer "In2.Cu")
		(net "M_B_CPU0_SA_CB<6>")
	)
	(segment
		(start 329.68565 -261.342886)
		(end 329.490324 -261.342886)
		(width 0.088646)
		(layer "In2.Cu")
		(net "M_B_CPU0_SA_CB<6>")
	)
	(segment
		(start 318.682878 -266.095988)
		(end 318.559688 -265.972798)
		(width 0.18288)
		(layer "In2.Cu")
		(net "M_B_CPU0_SA_CB<6>")
	)
	(segment
		(start 331.966062 -259.051806)
		(end 331.818234 -259.051806)
		(width 0.088646)
		(layer "In2.Cu")
		(net "M_B_CPU0_SA_CB<6>")
	)
	(segment
		(start 331.529436 -259.4991)
		(end 329.68565 -261.342886)
		(width 0.088646)
		(layer "In2.Cu")
		(net "M_B_CPU0_SA_CB<6>")
	)
	(segment
		(start 300.873668 -272.17497)
		(end 300.218348 -272.83029)
		(width 0.18288)
		(layer "In2.Cu")
		(net "M_B_CPU0_SA_CB<6>")
	)
	(segment
		(start 310.61787 -270.96212)
		(end 310.43372 -271.14627)
		(width 0.18288)
		(layer "In2.Cu")
		(net "M_B_CPU0_SA_CB<6>")
	)
	(segment
		(start 319.180464 -265.871198)
		(end 318.955674 -266.095988)
		(width 0.18288)
		(layer "In2.Cu")
		(net "M_B_CPU0_SA_CB<6>")
	)
	(segment
		(start 316.569344 -267.963142)
		(end 316.296548 -267.963142)
		(width 0.18288)
		(layer "In2.Cu")
		(net "M_B_CPU0_SA_CB<6>")
	)
	(segment
		(start 317.29172 -266.96797)
		(end 317.06693 -267.19276)
		(width 0.18288)
		(layer "In2.Cu")
		(net "M_B_CPU0_SA_CB<6>")
	)
	(segment
		(start 303.06518 -272.147792)
		(end 303.06518 -272.624042)
		(width 0.18288)
		(layer "In2.Cu")
		(net "M_B_CPU0_SA_CB<6>")
	)
	(segment
		(start 318.062102 -266.470384)
		(end 318.185292 -266.593574)
		(width 0.18288)
		(layer "In2.Cu")
		(net "M_B_CPU0_SA_CB<6>")
	)
	(segment
		(start 320.547238 -264.105644)
		(end 320.175636 -264.477246)
		(width 0.18288)
		(layer "In2.Cu")
		(net "M_B_CPU0_SA_CB<6>")
	)
	(segment
		(start 318.185292 -266.86637)
		(end 317.960502 -267.09116)
		(width 0.18288)
		(layer "In2.Cu")
		(net "M_B_CPU0_SA_CB<6>")
	)
	(segment
		(start 338.544662 -259.616956)
		(end 338.231988 -259.61721)
		(width 0.088646)
		(layer "In2.Cu")
		(net "M_B_CPU0_SA_CB<6>")
	)
	(segment
		(start 315.199776 -269.57909)
		(end 315.199776 -269.851886)
		(width 0.18288)
		(layer "In2.Cu")
		(net "M_B_CPU0_SA_CB<6>")
	)
	(segment
		(start 319.282064 -264.977626)
		(end 319.057274 -265.202416)
		(width 0.18288)
		(layer "In2.Cu")
		(net "M_B_CPU0_SA_CB<6>")
	)
	(segment
		(start 304.310542 -271.987772)
		(end 303.2252 -271.987772)
		(width 0.18288)
		(layer "In2.Cu")
		(net "M_B_CPU0_SA_CB<6>")
	)
	(segment
		(start 311.2897 -270.29029)
		(end 310.859932 -270.29029)
		(width 0.18288)
		(layer "In2.Cu")
		(net "M_B_CPU0_SA_CB<6>")
	)
	(segment
		(start 317.687706 -267.09116)
		(end 317.564516 -266.96797)
		(width 0.18288)
		(layer "In2.Cu")
		(net "M_B_CPU0_SA_CB<6>")
	)
	(segment
		(start 307.184552 -271.168368)
		(end 307.184552 -271.770856)
		(width 0.18288)
		(layer "In2.Cu")
		(net "M_B_CPU0_SA_CB<6>")
	)
	(segment
		(start 316.194948 -268.856714)
		(end 315.970158 -269.081504)
		(width 0.18288)
		(layer "In2.Cu")
		(net "M_B_CPU0_SA_CB<6>")
	)
	(segment
		(start 307.184552 -271.770856)
		(end 307.011832 -271.943576)
		(width 0.18288)
		(layer "In2.Cu")
		(net "M_B_CPU0_SA_CB<6>")
	)
	(segment
		(start 307.477668 -270.875252)
		(end 307.184552 -271.168368)
		(width 0.18288)
		(layer "In2.Cu")
		(net "M_B_CPU0_SA_CB<6>")
	)
	(segment
		(start 331.529436 -259.340604)
		(end 331.529436 -259.4991)
		(width 0.088646)
		(layer "In2.Cu")
		(net "M_B_CPU0_SA_CB<6>")
	)
	(segment
		(start 315.574172 -268.958314)
		(end 315.301376 -268.958314)
		(width 0.18288)
		(layer "In2.Cu")
		(net "M_B_CPU0_SA_CB<6>")
	)
	(segment
		(start 317.564516 -266.96797)
		(end 317.29172 -266.96797)
		(width 0.18288)
		(layer "In2.Cu")
		(net "M_B_CPU0_SA_CB<6>")
	)
	(segment
		(start 310.61787 -270.532352)
		(end 310.61787 -270.96212)
		(width 0.18288)
		(layer "In2.Cu")
		(net "M_B_CPU0_SA_CB<6>")
	)
	(segment
		(start 336.38236 -259.127752)
		(end 336.368898 -259.135372)
		(width 0.088646)
		(layer "In2.Cu")
		(net "M_B_CPU0_SA_CB<6>")
	)
	(segment
		(start 318.559688 -265.972798)
		(end 318.286892 -265.972798)
		(width 0.18288)
		(layer "In2.Cu")
		(net "M_B_CPU0_SA_CB<6>")
	)
	(segment
		(start 310.859932 -270.29029)
		(end 310.61787 -270.532352)
		(width 0.18288)
		(layer "In2.Cu")
		(net "M_B_CPU0_SA_CB<6>")
	)
	(segment
		(start 320.946018 -264.105644)
		(end 320.547238 -264.105644)
		(width 0.18288)
		(layer "In2.Cu")
		(net "M_B_CPU0_SA_CB<6>")
	)
	(segment
		(start 315.970158 -269.081504)
		(end 315.697362 -269.081504)
		(width 0.18288)
		(layer "In2.Cu")
		(net "M_B_CPU0_SA_CB<6>")
	)
	(segment
		(start 304.988468 -271.309846)
		(end 304.310542 -271.987772)
		(width 0.18288)
		(layer "In2.Cu")
		(net "M_B_CPU0_SA_CB<6>")
	)
	(segment
		(start 316.296548 -267.963142)
		(end 316.071758 -268.187932)
		(width 0.18288)
		(layer "In2.Cu")
		(net "M_B_CPU0_SA_CB<6>")
	)
	(segment
		(start 317.06693 -267.19276)
		(end 317.06693 -267.465556)
		(width 0.18288)
		(layer "In2.Cu")
		(net "M_B_CPU0_SA_CB<6>")
	)
	(segment
		(start 320.175636 -264.876026)
		(end 319.950846 -265.100816)
		(width 0.18288)
		(layer "In2.Cu")
		(net "M_B_CPU0_SA_CB<6>")
	)
	(segment
		(start 315.301376 -268.958314)
		(end 315.076586 -269.183104)
		(width 0.18288)
		(layer "In2.Cu")
		(net "M_B_CPU0_SA_CB<6>")
	)
	(segment
		(start 331.818234 -259.051806)
		(end 331.529436 -259.340604)
		(width 0.088646)
		(layer "In2.Cu")
		(net "M_B_CPU0_SA_CB<6>")
	)
	(segment
		(start 303.2252 -271.987772)
		(end 303.06518 -272.147792)
		(width 0.18288)
		(layer "In2.Cu")
		(net "M_B_CPU0_SA_CB<6>")
	)
	(segment
		(start 315.076586 -269.183104)
		(end 315.076586 -269.4559)
		(width 0.18288)
		(layer "In2.Cu")
		(net "M_B_CPU0_SA_CB<6>")
	)
	(segment
		(start 302.366934 -272.786856)
		(end 301.755048 -272.17497)
		(width 0.18288)
		(layer "In2.Cu")
		(net "M_B_CPU0_SA_CB<6>")
	)
	(arc
		(start 332.62316 -259.127498)
		(mid 332.435962 -259.177641)
		(end 332.248764 -259.127498)
		(width 0.088646)
		(layer "In2.Cu")
		(net "M_B_CPU0_SA_CB<6>")
	)
	(arc
		(start 334.128364 -259.127498)
		(mid 333.845662 -259.051722)
		(end 333.56296 -259.127498)
		(width 0.088646)
		(layer "In2.Cu")
		(net "M_B_CPU0_SA_CB<6>")
	)
	(arc
		(start 335.068164 -259.127498)
		(mid 334.785462 -259.051722)
		(end 334.50276 -259.127498)
		(width 0.088646)
		(layer "In2.Cu")
		(net "M_B_CPU0_SA_CB<6>")
	)
	(arc
		(start 336.368898 -259.135372)
		(mid 336.19718 -259.181784)
		(end 336.024982 -259.13715)
		(width 0.088646)
		(layer "In2.Cu")
		(net "M_B_CPU0_SA_CB<6>")
	)
	(arc
		(start 338.166456 -259.551678)
		(mid 337.85862 -259.111948)
		(end 337.32216 -259.127752)
		(width 0.088646)
		(layer "In2.Cu")
		(net "M_B_CPU0_SA_CB<6>")
	)
	(arc
		(start 334.50276 -259.127498)
		(mid 334.315562 -259.177641)
		(end 334.128364 -259.127498)
		(width 0.088646)
		(layer "In2.Cu")
		(net "M_B_CPU0_SA_CB<6>")
	)
	(arc
		(start 332.248764 -259.127498)
		(mid 332.112398 -259.07102)
		(end 331.966062 -259.051806)
		(width 0.088646)
		(layer "In2.Cu")
		(net "M_B_CPU0_SA_CB<6>")
	)
	(arc
		(start 333.188564 -259.127498)
		(mid 332.905862 -259.051722)
		(end 332.62316 -259.127498)
		(width 0.088646)
		(layer "In2.Cu")
		(net "M_B_CPU0_SA_CB<6>")
	)
	(arc
		(start 337.32216 -259.127752)
		(mid 337.134962 -259.177895)
		(end 336.947764 -259.127752)
		(width 0.088646)
		(layer "In2.Cu")
		(net "M_B_CPU0_SA_CB<6>")
	)
	(arc
		(start 335.44256 -259.127498)
		(mid 335.255362 -259.177641)
		(end 335.068164 -259.127498)
		(width 0.088646)
		(layer "In2.Cu")
		(net "M_B_CPU0_SA_CB<6>")
	)
	(arc
		(start 336.947764 -259.127752)
		(mid 336.665062 -259.051976)
		(end 336.38236 -259.127752)
		(width 0.088646)
		(layer "In2.Cu")
		(net "M_B_CPU0_SA_CB<6>")
	)
	(arc
		(start 336.007964 -259.127498)
		(mid 335.725262 -259.051722)
		(end 335.44256 -259.127498)
		(width 0.088646)
		(layer "In2.Cu")
		(net "M_B_CPU0_SA_CB<6>")
	)
	(arc
		(start 333.56296 -259.127498)
		(mid 333.375762 -259.177641)
		(end 333.188564 -259.127498)
		(width 0.088646)
		(layer "In2.Cu")
		(net "M_B_CPU0_SA_CB<6>")
	)
	(segment
		(start 337.134962 -258.2672)
		(end 337.134962 -258.80314)
		(width 0.20066)
		(layer "F.Cu")
		(net "M_B_CPU0_SA_CB<5>")
	)
	(segment
		(start 287.589976 -271.266666)
		(end 286.255714 -271.266666)
		(width 0.20066)
		(layer "F.Cu")
		(net "M_B_CPU0_SA_CB<5>")
	)
	(segment
		(start 289.240468 -270.841724)
		(end 289.231578 -270.832834)
		(width 0.1016)
		(layer "F.Cu")
		(net "M_B_CPU0_SA_CB<5>")
	)
	(segment
		(start 294.904414 -271.266666)
		(end 293.799514 -271.266666)
		(width 0.20066)
		(layer "F.Cu")
		(net "M_B_CPU0_SA_CB<5>")
	)
	(segment
		(start 292.160198 -271.266666)
		(end 291.735256 -270.841724)
		(width 0.20066)
		(layer "F.Cu")
		(net "M_B_CPU0_SA_CB<5>")
	)
	(segment
		(start 291.225986 -270.841724)
		(end 289.240468 -270.841724)
		(width 0.1016)
		(layer "F.Cu")
		(net "M_B_CPU0_SA_CB<5>")
	)
	(segment
		(start 287.801304 -271.477994)
		(end 287.589976 -271.266666)
		(width 0.20066)
		(layer "F.Cu")
		(net "M_B_CPU0_SA_CB<5>")
	)
	(segment
		(start 288.46018 -271.323562)
		(end 288.305748 -271.477994)
		(width 0.20066)
		(layer "F.Cu")
		(net "M_B_CPU0_SA_CB<5>")
	)
	(segment
		(start 289.231578 -270.832834)
		(end 288.62274 -270.832834)
		(width 0.20066)
		(layer "F.Cu")
		(net "M_B_CPU0_SA_CB<5>")
	)
	(segment
		(start 293.799514 -271.266666)
		(end 292.160198 -271.266666)
		(width 0.20066)
		(layer "F.Cu")
		(net "M_B_CPU0_SA_CB<5>")
	)
	(segment
		(start 288.46018 -270.995394)
		(end 288.46018 -271.323562)
		(width 0.20066)
		(layer "F.Cu")
		(net "M_B_CPU0_SA_CB<5>")
	)
	(segment
		(start 291.556694 -270.841724)
		(end 291.225986 -270.841724)
		(width 0.101854)
		(layer "F.Cu")
		(net "M_B_CPU0_SA_CB<5>")
	)
	(segment
		(start 288.305748 -271.477994)
		(end 287.801304 -271.477994)
		(width 0.20066)
		(layer "F.Cu")
		(net "M_B_CPU0_SA_CB<5>")
	)
	(segment
		(start 291.735256 -270.841724)
		(end 291.556694 -270.841724)
		(width 0.20066)
		(layer "F.Cu")
		(net "M_B_CPU0_SA_CB<5>")
	)
	(segment
		(start 288.62274 -270.832834)
		(end 288.46018 -270.995394)
		(width 0.20066)
		(layer "F.Cu")
		(net "M_B_CPU0_SA_CB<5>")
	)
	(segment
		(start 325.222616 -260.997446)
		(end 324.167246 -262.052816)
		(width 0.18288)
		(layer "In2.Cu")
		(net "M_B_CPU0_SA_CB<5>")
	)
	(segment
		(start 302.181768 -271.665954)
		(end 299.528484 -271.665954)
		(width 0.18288)
		(layer "In2.Cu")
		(net "M_B_CPU0_SA_CB<5>")
	)
	(segment
		(start 296.8498 -271.881092)
		(end 296.45991 -271.881092)
		(width 0.18288)
		(layer "In2.Cu")
		(net "M_B_CPU0_SA_CB<5>")
	)
	(segment
		(start 295.56329 -270.351758)
		(end 295.56329 -271.073626)
		(width 0.18288)
		(layer "In2.Cu")
		(net "M_B_CPU0_SA_CB<5>")
	)
	(segment
		(start 295.774364 -270.140684)
		(end 295.56329 -270.351758)
		(width 0.18288)
		(layer "In2.Cu")
		(net "M_B_CPU0_SA_CB<5>")
	)
	(segment
		(start 307.570378 -269.967202)
		(end 306.745132 -270.792448)
		(width 0.18288)
		(layer "In2.Cu")
		(net "M_B_CPU0_SA_CB<5>")
	)
	(segment
		(start 330.146406 -260.445504)
		(end 330.146406 -260.529324)
		(width 0.088646)
		(layer "In2.Cu")
		(net "M_B_CPU0_SA_CB<5>")
	)
	(segment
		(start 308.375558 -270.36014)
		(end 307.98262 -269.967202)
		(width 0.18288)
		(layer "In2.Cu")
		(net "M_B_CPU0_SA_CB<5>")
	)
	(segment
		(start 329.490324 -260.997446)
		(end 325.222616 -260.997446)
		(width 0.18288)
		(layer "In2.Cu")
		(net "M_B_CPU0_SA_CB<5>")
	)
	(segment
		(start 329.678284 -260.997446)
		(end 329.490324 -260.997446)
		(width 0.088646)
		(layer "In2.Cu")
		(net "M_B_CPU0_SA_CB<5>")
	)
	(segment
		(start 296.07383 -270.140684)
		(end 295.774364 -270.140684)
		(width 0.18288)
		(layer "In2.Cu")
		(net "M_B_CPU0_SA_CB<5>")
	)
	(segment
		(start 302.378364 -271.469358)
		(end 302.181768 -271.665954)
		(width 0.18288)
		(layer "In2.Cu")
		(net "M_B_CPU0_SA_CB<5>")
	)
	(segment
		(start 295.56329 -271.073626)
		(end 295.37025 -271.266666)
		(width 0.18288)
		(layer "In2.Cu")
		(net "M_B_CPU0_SA_CB<5>")
	)
	(segment
		(start 298.338494 -271.691862)
		(end 297.825414 -271.178782)
		(width 0.18288)
		(layer "In2.Cu")
		(net "M_B_CPU0_SA_CB<5>")
	)
	(segment
		(start 304.15357 -270.792448)
		(end 303.47666 -271.469358)
		(width 0.18288)
		(layer "In2.Cu")
		(net "M_B_CPU0_SA_CB<5>")
	)
	(segment
		(start 331.804264 -258.787646)
		(end 330.146406 -260.445504)
		(width 0.088646)
		(layer "In2.Cu")
		(net "M_B_CPU0_SA_CB<5>")
	)
	(segment
		(start 337.33105 -258.483862)
		(end 337.32216 -258.478782)
		(width 0.088646)
		(layer "In2.Cu")
		(net "M_B_CPU0_SA_CB<5>")
	)
	(segment
		(start 297.55211 -271.178782)
		(end 296.8498 -271.881092)
		(width 0.18288)
		(layer "In2.Cu")
		(net "M_B_CPU0_SA_CB<5>")
	)
	(segment
		(start 295.37025 -271.266666)
		(end 294.904414 -271.266666)
		(width 0.18288)
		(layer "In2.Cu")
		(net "M_B_CPU0_SA_CB<5>")
	)
	(segment
		(start 309.516018 -269.99184)
		(end 309.147718 -270.36014)
		(width 0.18288)
		(layer "In2.Cu")
		(net "M_B_CPU0_SA_CB<5>")
	)
	(segment
		(start 303.47666 -271.469358)
		(end 302.378364 -271.469358)
		(width 0.18288)
		(layer "In2.Cu")
		(net "M_B_CPU0_SA_CB<5>")
	)
	(segment
		(start 296.26687 -271.688052)
		(end 296.26687 -270.333724)
		(width 0.18288)
		(layer "In2.Cu")
		(net "M_B_CPU0_SA_CB<5>")
	)
	(segment
		(start 319.592452 -263.948418)
		(end 314.399168 -269.141702)
		(width 0.18288)
		(layer "In2.Cu")
		(net "M_B_CPU0_SA_CB<5>")
	)
	(segment
		(start 299.528484 -271.665954)
		(end 299.502576 -271.691862)
		(width 0.18288)
		(layer "In2.Cu")
		(net "M_B_CPU0_SA_CB<5>")
	)
	(segment
		(start 332.162658 -258.519168)
		(end 331.89418 -258.787646)
		(width 0.088646)
		(layer "In2.Cu")
		(net "M_B_CPU0_SA_CB<5>")
	)
	(segment
		(start 312.519314 -269.495524)
		(end 312.158888 -269.135098)
		(width 0.18288)
		(layer "In2.Cu")
		(net "M_B_CPU0_SA_CB<5>")
	)
	(segment
		(start 311.579768 -269.135098)
		(end 311.039256 -269.67561)
		(width 0.18288)
		(layer "In2.Cu")
		(net "M_B_CPU0_SA_CB<5>")
	)
	(segment
		(start 311.039256 -269.67561)
		(end 310.752236 -269.67561)
		(width 0.18288)
		(layer "In2.Cu")
		(net "M_B_CPU0_SA_CB<5>")
	)
	(segment
		(start 310.752236 -269.67561)
		(end 310.436006 -269.99184)
		(width 0.18288)
		(layer "In2.Cu")
		(net "M_B_CPU0_SA_CB<5>")
	)
	(segment
		(start 331.89418 -258.787646)
		(end 331.804264 -258.787646)
		(width 0.088646)
		(layer "In2.Cu")
		(net "M_B_CPU0_SA_CB<5>")
	)
	(segment
		(start 306.745132 -270.792448)
		(end 304.15357 -270.792448)
		(width 0.18288)
		(layer "In2.Cu")
		(net "M_B_CPU0_SA_CB<5>")
	)
	(segment
		(start 337.134962 -258.80314)
		(end 337.44789 -258.80314)
		(width 0.088646)
		(layer "In2.Cu")
		(net "M_B_CPU0_SA_CB<5>")
	)
	(segment
		(start 309.147718 -270.36014)
		(end 308.375558 -270.36014)
		(width 0.18288)
		(layer "In2.Cu")
		(net "M_B_CPU0_SA_CB<5>")
	)
	(segment
		(start 307.98262 -269.967202)
		(end 307.570378 -269.967202)
		(width 0.18288)
		(layer "In2.Cu")
		(net "M_B_CPU0_SA_CB<5>")
	)
	(segment
		(start 324.167246 -262.052816)
		(end 319.592452 -263.948418)
		(width 0.18288)
		(layer "In2.Cu")
		(net "M_B_CPU0_SA_CB<5>")
	)
	(segment
		(start 330.146406 -260.529324)
		(end 329.678284 -260.997446)
		(width 0.088646)
		(layer "In2.Cu")
		(net "M_B_CPU0_SA_CB<5>")
	)
	(segment
		(start 313.251342 -269.495524)
		(end 312.519314 -269.495524)
		(width 0.18288)
		(layer "In2.Cu")
		(net "M_B_CPU0_SA_CB<5>")
	)
	(segment
		(start 296.45991 -271.881092)
		(end 296.26687 -271.688052)
		(width 0.18288)
		(layer "In2.Cu")
		(net "M_B_CPU0_SA_CB<5>")
	)
	(segment
		(start 313.605164 -269.141702)
		(end 313.251342 -269.495524)
		(width 0.18288)
		(layer "In2.Cu")
		(net "M_B_CPU0_SA_CB<5>")
	)
	(segment
		(start 297.825414 -271.178782)
		(end 297.55211 -271.178782)
		(width 0.18288)
		(layer "In2.Cu")
		(net "M_B_CPU0_SA_CB<5>")
	)
	(segment
		(start 312.158888 -269.135098)
		(end 311.579768 -269.135098)
		(width 0.18288)
		(layer "In2.Cu")
		(net "M_B_CPU0_SA_CB<5>")
	)
	(segment
		(start 299.502576 -271.691862)
		(end 298.338494 -271.691862)
		(width 0.18288)
		(layer "In2.Cu")
		(net "M_B_CPU0_SA_CB<5>")
	)
	(segment
		(start 296.26687 -270.333724)
		(end 296.07383 -270.140684)
		(width 0.18288)
		(layer "In2.Cu")
		(net "M_B_CPU0_SA_CB<5>")
	)
	(segment
		(start 337.44789 -258.80314)
		(end 337.50504 -258.74599)
		(width 0.088646)
		(layer "In2.Cu")
		(net "M_B_CPU0_SA_CB<5>")
	)
	(segment
		(start 314.399168 -269.141702)
		(end 313.605164 -269.141702)
		(width 0.18288)
		(layer "In2.Cu")
		(net "M_B_CPU0_SA_CB<5>")
	)
	(segment
		(start 310.436006 -269.99184)
		(end 309.516018 -269.99184)
		(width 0.18288)
		(layer "In2.Cu")
		(net "M_B_CPU0_SA_CB<5>")
	)
	(arc
		(start 337.32216 -258.478782)
		(mid 337.134962 -258.428639)
		(end 336.947764 -258.478782)
		(width 0.088646)
		(layer "In2.Cu")
		(net "M_B_CPU0_SA_CB<5>")
	)
	(arc
		(start 336.38236 -258.478782)
		(mid 336.195162 -258.428639)
		(end 336.007964 -258.478782)
		(width 0.088646)
		(layer "In2.Cu")
		(net "M_B_CPU0_SA_CB<5>")
	)
	(arc
		(start 337.50504 -258.74599)
		(mid 337.446921 -258.595749)
		(end 337.33105 -258.483862)
		(width 0.088646)
		(layer "In2.Cu")
		(net "M_B_CPU0_SA_CB<5>")
	)
	(arc
		(start 333.188564 -258.478782)
		(mid 332.905862 -258.554524)
		(end 332.62316 -258.478782)
		(width 0.088646)
		(layer "In2.Cu")
		(net "M_B_CPU0_SA_CB<5>")
	)
	(arc
		(start 335.068164 -258.478782)
		(mid 334.785462 -258.554524)
		(end 334.50276 -258.478782)
		(width 0.088646)
		(layer "In2.Cu")
		(net "M_B_CPU0_SA_CB<5>")
	)
	(arc
		(start 332.248764 -258.478782)
		(mid 332.206565 -258.500796)
		(end 332.162658 -258.519168)
		(width 0.088646)
		(layer "In2.Cu")
		(net "M_B_CPU0_SA_CB<5>")
	)
	(arc
		(start 333.56296 -258.478782)
		(mid 333.375762 -258.428639)
		(end 333.188564 -258.478782)
		(width 0.088646)
		(layer "In2.Cu")
		(net "M_B_CPU0_SA_CB<5>")
	)
	(arc
		(start 332.62316 -258.478782)
		(mid 332.435962 -258.428639)
		(end 332.248764 -258.478782)
		(width 0.088646)
		(layer "In2.Cu")
		(net "M_B_CPU0_SA_CB<5>")
	)
	(arc
		(start 335.44256 -258.478782)
		(mid 335.255362 -258.428639)
		(end 335.068164 -258.478782)
		(width 0.088646)
		(layer "In2.Cu")
		(net "M_B_CPU0_SA_CB<5>")
	)
	(arc
		(start 336.007964 -258.478782)
		(mid 335.725262 -258.554524)
		(end 335.44256 -258.478782)
		(width 0.088646)
		(layer "In2.Cu")
		(net "M_B_CPU0_SA_CB<5>")
	)
	(arc
		(start 336.947764 -258.478782)
		(mid 336.665062 -258.554524)
		(end 336.38236 -258.478782)
		(width 0.088646)
		(layer "In2.Cu")
		(net "M_B_CPU0_SA_CB<5>")
	)
	(arc
		(start 334.50276 -258.478782)
		(mid 334.315562 -258.428639)
		(end 334.128364 -258.478782)
		(width 0.088646)
		(layer "In2.Cu")
		(net "M_B_CPU0_SA_CB<5>")
	)
	(arc
		(start 334.128364 -258.478782)
		(mid 333.845662 -258.554524)
		(end 333.56296 -258.478782)
		(width 0.088646)
		(layer "In2.Cu")
		(net "M_B_CPU0_SA_CB<5>")
	)
	(segment
		(start 289.231578 -272.533618)
		(end 288.66973 -272.533618)
		(width 0.20066)
		(layer "F.Cu")
		(net "M_B_CPU0_SA_CB<4>")
	)
	(segment
		(start 291.556694 -272.541746)
		(end 289.48761 -272.541746)
		(width 0.1016)
		(layer "F.Cu")
		(net "M_B_CPU0_SA_CB<4>")
	)
	(segment
		(start 288.46018 -273.032728)
		(end 288.28746 -273.205448)
		(width 0.20066)
		(layer "F.Cu")
		(net "M_B_CPU0_SA_CB<4>")
	)
	(segment
		(start 287.589976 -272.966688)
		(end 286.255714 -272.966688)
		(width 0.20066)
		(layer "F.Cu")
		(net "M_B_CPU0_SA_CB<4>")
	)
	(segment
		(start 293.799514 -272.966688)
		(end 292.430454 -272.966688)
		(width 0.20066)
		(layer "F.Cu")
		(net "M_B_CPU0_SA_CB<4>")
	)
	(segment
		(start 288.28746 -273.205448)
		(end 287.828736 -273.205448)
		(width 0.20066)
		(layer "F.Cu")
		(net "M_B_CPU0_SA_CB<4>")
	)
	(segment
		(start 287.828736 -273.205448)
		(end 287.589976 -272.966688)
		(width 0.20066)
		(layer "F.Cu")
		(net "M_B_CPU0_SA_CB<4>")
	)
	(segment
		(start 288.66973 -272.533618)
		(end 288.46018 -272.743168)
		(width 0.20066)
		(layer "F.Cu")
		(net "M_B_CPU0_SA_CB<4>")
	)
	(segment
		(start 292.430454 -272.966688)
		(end 292.005512 -272.541746)
		(width 0.20066)
		(layer "F.Cu")
		(net "M_B_CPU0_SA_CB<4>")
	)
	(segment
		(start 289.239706 -272.541746)
		(end 289.231578 -272.533618)
		(width 0.101854)
		(layer "F.Cu")
		(net "M_B_CPU0_SA_CB<4>")
	)
	(segment
		(start 336.665316 -259.081016)
		(end 336.665062 -259.08127)
		(width 0.20066)
		(layer "F.Cu")
		(net "M_B_CPU0_SA_CB<4>")
	)
	(segment
		(start 289.48761 -272.541746)
		(end 289.239706 -272.541746)
		(width 0.101854)
		(layer "F.Cu")
		(net "M_B_CPU0_SA_CB<4>")
	)
	(segment
		(start 294.904414 -272.966688)
		(end 293.799514 -272.966688)
		(width 0.20066)
		(layer "F.Cu")
		(net "M_B_CPU0_SA_CB<4>")
	)
	(segment
		(start 288.46018 -272.743168)
		(end 288.46018 -273.032728)
		(width 0.20066)
		(layer "F.Cu")
		(net "M_B_CPU0_SA_CB<4>")
	)
	(segment
		(start 336.665062 -259.08127)
		(end 336.665062 -259.616956)
		(width 0.20066)
		(layer "F.Cu")
		(net "M_B_CPU0_SA_CB<4>")
	)
	(segment
		(start 292.005512 -272.541746)
		(end 291.556694 -272.541746)
		(width 0.20066)
		(layer "F.Cu")
		(net "M_B_CPU0_SA_CB<4>")
	)
	(segment
		(start 314.97016 -270.809212)
		(end 311.495694 -270.809212)
		(width 0.18288)
		(layer "In2.Cu")
		(net "M_B_CPU0_SA_CB<4>")
	)
	(segment
		(start 299.611034 -273.39163)
		(end 298.335446 -273.39163)
		(width 0.18288)
		(layer "In2.Cu")
		(net "M_B_CPU0_SA_CB<4>")
	)
	(segment
		(start 324.74027 -262.917432)
		(end 321.533774 -264.245598)
		(width 0.18288)
		(layer "In2.Cu")
		(net "M_B_CPU0_SA_CB<4>")
	)
	(segment
		(start 295.889426 -273.93519)
		(end 295.889426 -273.32813)
		(width 0.18288)
		(layer "In2.Cu")
		(net "M_B_CPU0_SA_CB<4>")
	)
	(segment
		(start 306.520088 -272.458434)
		(end 306.465732 -272.51279)
		(width 0.18288)
		(layer "In2.Cu")
		(net "M_B_CPU0_SA_CB<4>")
	)
	(segment
		(start 296.875454 -273.424396)
		(end 296.66311 -273.63674)
		(width 0.18288)
		(layer "In2.Cu")
		(net "M_B_CPU0_SA_CB<4>")
	)
	(segment
		(start 310.645556 -271.65935)
		(end 309.913274 -271.65935)
		(width 0.18288)
		(layer "In2.Cu")
		(net "M_B_CPU0_SA_CB<4>")
	)
	(segment
		(start 295.889426 -273.32813)
		(end 296.097706 -273.11985)
		(width 0.18288)
		(layer "In2.Cu")
		(net "M_B_CPU0_SA_CB<4>")
	)
	(segment
		(start 296.097706 -272.665444)
		(end 295.904412 -272.47215)
		(width 0.18288)
		(layer "In2.Cu")
		(net "M_B_CPU0_SA_CB<4>")
	)
	(segment
		(start 298.335446 -273.39163)
		(end 298.175426 -273.23161)
		(width 0.18288)
		(layer "In2.Cu")
		(net "M_B_CPU0_SA_CB<4>")
	)
	(segment
		(start 303.578006 -272.687542)
		(end 303.578006 -273.162522)
		(width 0.18288)
		(layer "In2.Cu")
		(net "M_B_CPU0_SA_CB<4>")
	)
	(segment
		(start 331.897736 -259.264912)
		(end 331.73543 -259.427218)
		(width 0.088646)
		(layer "In2.Cu")
		(net "M_B_CPU0_SA_CB<4>")
	)
	(segment
		(start 332.094078 -259.264912)
		(end 331.897736 -259.264912)
		(width 0.088646)
		(layer "In2.Cu")
		(net "M_B_CPU0_SA_CB<4>")
	)
	(segment
		(start 336.150712 -259.431282)
		(end 335.91246 -259.292598)
		(width 0.088646)
		(layer "In2.Cu")
		(net "M_B_CPU0_SA_CB<4>")
	)
	(segment
		(start 296.082466 -274.12823)
		(end 295.889426 -273.93519)
		(width 0.18288)
		(layer "In2.Cu")
		(net "M_B_CPU0_SA_CB<4>")
	)
	(segment
		(start 299.656246 -273.346418)
		(end 299.611034 -273.39163)
		(width 0.18288)
		(layer "In2.Cu")
		(net "M_B_CPU0_SA_CB<4>")
	)
	(segment
		(start 331.73543 -259.644642)
		(end 329.691746 -261.688326)
		(width 0.088646)
		(layer "In2.Cu")
		(net "M_B_CPU0_SA_CB<4>")
	)
	(segment
		(start 308.487064 -271.912588)
		(end 308.487064 -272.378932)
		(width 0.18288)
		(layer "In2.Cu")
		(net "M_B_CPU0_SA_CB<4>")
	)
	(segment
		(start 298.175426 -273.23161)
		(end 298.175426 -272.702782)
		(width 0.18288)
		(layer "In2.Cu")
		(net "M_B_CPU0_SA_CB<4>")
	)
	(segment
		(start 325.969376 -261.688326)
		(end 324.74027 -262.917432)
		(width 0.18288)
		(layer "In2.Cu")
		(net "M_B_CPU0_SA_CB<4>")
	)
	(segment
		(start 303.39411 -273.346418)
		(end 299.656246 -273.346418)
		(width 0.18288)
		(layer "In2.Cu")
		(net "M_B_CPU0_SA_CB<4>")
	)
	(segment
		(start 321.533774 -264.245598)
		(end 314.97016 -270.809212)
		(width 0.18288)
		(layer "In2.Cu")
		(net "M_B_CPU0_SA_CB<4>")
	)
	(segment
		(start 298.015406 -272.542762)
		(end 297.60291 -272.542762)
		(width 0.18288)
		(layer "In2.Cu")
		(net "M_B_CPU0_SA_CB<4>")
	)
	(segment
		(start 309.913274 -271.65935)
		(end 309.875936 -271.696688)
		(width 0.18288)
		(layer "In2.Cu")
		(net "M_B_CPU0_SA_CB<4>")
	)
	(segment
		(start 306.465732 -272.51279)
		(end 303.752758 -272.51279)
		(width 0.18288)
		(layer "In2.Cu")
		(net "M_B_CPU0_SA_CB<4>")
	)
	(segment
		(start 307.34635 -272.571972)
		(end 307.232812 -272.458434)
		(width 0.18288)
		(layer "In2.Cu")
		(net "M_B_CPU0_SA_CB<4>")
	)
	(segment
		(start 296.47007 -274.12823)
		(end 296.082466 -274.12823)
		(width 0.18288)
		(layer "In2.Cu")
		(net "M_B_CPU0_SA_CB<4>")
	)
	(segment
		(start 336.665062 -259.616956)
		(end 336.150712 -259.431282)
		(width 0.088646)
		(layer "In2.Cu")
		(net "M_B_CPU0_SA_CB<4>")
	)
	(segment
		(start 298.175426 -272.702782)
		(end 298.015406 -272.542762)
		(width 0.18288)
		(layer "In2.Cu")
		(net "M_B_CPU0_SA_CB<4>")
	)
	(segment
		(start 295.398952 -272.47215)
		(end 294.904414 -272.966688)
		(width 0.18288)
		(layer "In2.Cu")
		(net "M_B_CPU0_SA_CB<4>")
	)
	(segment
		(start 308.702964 -271.696688)
		(end 308.487064 -271.912588)
		(width 0.18288)
		(layer "In2.Cu")
		(net "M_B_CPU0_SA_CB<4>")
	)
	(segment
		(start 329.490324 -261.688326)
		(end 325.969376 -261.688326)
		(width 0.18288)
		(layer "In2.Cu")
		(net "M_B_CPU0_SA_CB<4>")
	)
	(segment
		(start 329.691746 -261.688326)
		(end 329.490324 -261.688326)
		(width 0.088646)
		(layer "In2.Cu")
		(net "M_B_CPU0_SA_CB<4>")
	)
	(segment
		(start 308.294024 -272.571972)
		(end 307.34635 -272.571972)
		(width 0.18288)
		(layer "In2.Cu")
		(net "M_B_CPU0_SA_CB<4>")
	)
	(segment
		(start 296.66311 -273.63674)
		(end 296.66311 -273.93519)
		(width 0.18288)
		(layer "In2.Cu")
		(net "M_B_CPU0_SA_CB<4>")
	)
	(segment
		(start 297.229784 -273.424396)
		(end 296.875454 -273.424396)
		(width 0.18288)
		(layer "In2.Cu")
		(net "M_B_CPU0_SA_CB<4>")
	)
	(segment
		(start 296.66311 -273.93519)
		(end 296.47007 -274.12823)
		(width 0.18288)
		(layer "In2.Cu")
		(net "M_B_CPU0_SA_CB<4>")
	)
	(segment
		(start 303.578006 -273.162522)
		(end 303.39411 -273.346418)
		(width 0.18288)
		(layer "In2.Cu")
		(net "M_B_CPU0_SA_CB<4>")
	)
	(segment
		(start 295.904412 -272.47215)
		(end 295.398952 -272.47215)
		(width 0.18288)
		(layer "In2.Cu")
		(net "M_B_CPU0_SA_CB<4>")
	)
	(segment
		(start 297.399456 -273.254724)
		(end 297.229784 -273.424396)
		(width 0.18288)
		(layer "In2.Cu")
		(net "M_B_CPU0_SA_CB<4>")
	)
	(segment
		(start 311.495694 -270.809212)
		(end 310.645556 -271.65935)
		(width 0.18288)
		(layer "In2.Cu")
		(net "M_B_CPU0_SA_CB<4>")
	)
	(segment
		(start 303.752758 -272.51279)
		(end 303.578006 -272.687542)
		(width 0.18288)
		(layer "In2.Cu")
		(net "M_B_CPU0_SA_CB<4>")
	)
	(segment
		(start 309.875936 -271.696688)
		(end 308.702964 -271.696688)
		(width 0.18288)
		(layer "In2.Cu")
		(net "M_B_CPU0_SA_CB<4>")
	)
	(segment
		(start 297.60291 -272.542762)
		(end 297.399456 -272.746216)
		(width 0.18288)
		(layer "In2.Cu")
		(net "M_B_CPU0_SA_CB<4>")
	)
	(segment
		(start 296.097706 -273.11985)
		(end 296.097706 -272.665444)
		(width 0.18288)
		(layer "In2.Cu")
		(net "M_B_CPU0_SA_CB<4>")
	)
	(segment
		(start 331.73543 -259.427218)
		(end 331.73543 -259.644642)
		(width 0.088646)
		(layer "In2.Cu")
		(net "M_B_CPU0_SA_CB<4>")
	)
	(segment
		(start 308.487064 -272.378932)
		(end 308.294024 -272.571972)
		(width 0.18288)
		(layer "In2.Cu")
		(net "M_B_CPU0_SA_CB<4>")
	)
	(segment
		(start 307.232812 -272.458434)
		(end 306.520088 -272.458434)
		(width 0.18288)
		(layer "In2.Cu")
		(net "M_B_CPU0_SA_CB<4>")
	)
	(segment
		(start 297.399456 -272.746216)
		(end 297.399456 -273.254724)
		(width 0.18288)
		(layer "In2.Cu")
		(net "M_B_CPU0_SA_CB<4>")
	)
	(arc
		(start 333.09306 -259.292598)
		(mid 332.905862 -259.242455)
		(end 332.718664 -259.292598)
		(width 0.088646)
		(layer "In2.Cu")
		(net "M_B_CPU0_SA_CB<4>")
	)
	(arc
		(start 332.15326 -259.292598)
		(mid 332.124278 -259.277452)
		(end 332.094078 -259.264912)
		(width 0.088646)
		(layer "In2.Cu")
		(net "M_B_CPU0_SA_CB<4>")
	)
	(arc
		(start 334.97266 -259.292598)
		(mid 334.785462 -259.242455)
		(end 334.598264 -259.292598)
		(width 0.088646)
		(layer "In2.Cu")
		(net "M_B_CPU0_SA_CB<4>")
	)
	(arc
		(start 333.658464 -259.292598)
		(mid 333.375762 -259.368374)
		(end 333.09306 -259.292598)
		(width 0.088646)
		(layer "In2.Cu")
		(net "M_B_CPU0_SA_CB<4>")
	)
	(arc
		(start 335.538064 -259.292598)
		(mid 335.255362 -259.36834)
		(end 334.97266 -259.292598)
		(width 0.088646)
		(layer "In2.Cu")
		(net "M_B_CPU0_SA_CB<4>")
	)
	(arc
		(start 335.91246 -259.292598)
		(mid 335.725262 -259.242455)
		(end 335.538064 -259.292598)
		(width 0.088646)
		(layer "In2.Cu")
		(net "M_B_CPU0_SA_CB<4>")
	)
	(arc
		(start 332.718664 -259.292598)
		(mid 332.435962 -259.368374)
		(end 332.15326 -259.292598)
		(width 0.088646)
		(layer "In2.Cu")
		(net "M_B_CPU0_SA_CB<4>")
	)
	(arc
		(start 334.598264 -259.292598)
		(mid 334.315562 -259.368374)
		(end 334.03286 -259.292598)
		(width 0.088646)
		(layer "In2.Cu")
		(net "M_B_CPU0_SA_CB<4>")
	)
	(arc
		(start 334.03286 -259.292598)
		(mid 333.845662 -259.242455)
		(end 333.658464 -259.292598)
		(width 0.088646)
		(layer "In2.Cu")
		(net "M_B_CPU0_SA_CB<4>")
	)
	(segment
		(start 292.05301 -276.366732)
		(end 292.178994 -276.492716)
		(width 0.20066)
		(layer "F.Cu")
		(net "M_B_CPU0_SA_CB<3>")
	)
	(segment
		(start 292.178994 -276.663404)
		(end 292.321488 -276.805898)
		(width 0.20066)
		(layer "F.Cu")
		(net "M_B_CPU0_SA_CB<3>")
	)
	(segment
		(start 299.029628 -276.366732)
		(end 297.899582 -276.366732)
		(width 0.20066)
		(layer "F.Cu")
		(net "M_B_CPU0_SA_CB<3>")
	)
	(segment
		(start 290.355782 -276.366732)
		(end 292.05301 -276.366732)
		(width 0.20066)
		(layer "F.Cu")
		(net "M_B_CPU0_SA_CB<3>")
	)
	(segment
		(start 292.67531 -276.805898)
		(end 292.689534 -276.791674)
		(width 0.101854)
		(layer "F.Cu")
		(net "M_B_CPU0_SA_CB<3>")
	)
	(segment
		(start 292.927532 -276.791674)
		(end 295.000426 -276.791674)
		(width 0.1016)
		(layer "F.Cu")
		(net "M_B_CPU0_SA_CB<3>")
	)
	(segment
		(start 338.544662 -260.709156)
		(end 338.544662 -261.244842)
		(width 0.20066)
		(layer "F.Cu")
		(net "M_B_CPU0_SA_CB<3>")
	)
	(segment
		(start 295.693846 -276.642576)
		(end 295.693846 -276.490938)
		(width 0.20066)
		(layer "F.Cu")
		(net "M_B_CPU0_SA_CB<3>")
	)
	(segment
		(start 296.42943 -276.57425)
		(end 296.875962 -276.57425)
		(width 0.20066)
		(layer "F.Cu")
		(net "M_B_CPU0_SA_CB<3>")
	)
	(segment
		(start 296.217594 -276.362414)
		(end 296.42943 -276.57425)
		(width 0.20066)
		(layer "F.Cu")
		(net "M_B_CPU0_SA_CB<3>")
	)
	(segment
		(start 292.321488 -276.805898)
		(end 292.67531 -276.805898)
		(width 0.20066)
		(layer "F.Cu")
		(net "M_B_CPU0_SA_CB<3>")
	)
	(segment
		(start 296.875962 -276.57425)
		(end 297.08348 -276.366732)
		(width 0.20066)
		(layer "F.Cu")
		(net "M_B_CPU0_SA_CB<3>")
	)
	(segment
		(start 292.178994 -276.492716)
		(end 292.178994 -276.663404)
		(width 0.20066)
		(layer "F.Cu")
		(net "M_B_CPU0_SA_CB<3>")
	)
	(segment
		(start 338.544916 -260.708902)
		(end 338.544662 -260.709156)
		(width 0.20066)
		(layer "F.Cu")
		(net "M_B_CPU0_SA_CB<3>")
	)
	(segment
		(start 295.000426 -276.791674)
		(end 295.544748 -276.791674)
		(width 0.20066)
		(layer "F.Cu")
		(net "M_B_CPU0_SA_CB<3>")
	)
	(segment
		(start 295.693846 -276.490938)
		(end 295.82237 -276.362414)
		(width 0.20066)
		(layer "F.Cu")
		(net "M_B_CPU0_SA_CB<3>")
	)
	(segment
		(start 292.689534 -276.791674)
		(end 292.927532 -276.791674)
		(width 0.101854)
		(layer "F.Cu")
		(net "M_B_CPU0_SA_CB<3>")
	)
	(segment
		(start 295.82237 -276.362414)
		(end 296.217594 -276.362414)
		(width 0.20066)
		(layer "F.Cu")
		(net "M_B_CPU0_SA_CB<3>")
	)
	(segment
		(start 297.08348 -276.366732)
		(end 297.899582 -276.366732)
		(width 0.20066)
		(layer "F.Cu")
		(net "M_B_CPU0_SA_CB<3>")
	)
	(segment
		(start 295.544748 -276.791674)
		(end 295.693846 -276.642576)
		(width 0.20066)
		(layer "F.Cu")
		(net "M_B_CPU0_SA_CB<3>")
	)
	(segment
		(start 299.029882 -276.366986)
		(end 299.029628 -276.366732)
		(width 0.20066)
		(layer "F.Cu")
		(net "M_B_CPU0_SA_CB<3>")
	)
	(segment
		(start 303.56175 -276.13483)
		(end 303.36871 -276.32787)
		(width 0.18288)
		(layer "In2.Cu")
		(net "M_B_CPU0_SA_CB<3>")
	)
	(segment
		(start 299.666152 -277.003256)
		(end 299.029882 -276.366986)
		(width 0.18288)
		(layer "In2.Cu")
		(net "M_B_CPU0_SA_CB<3>")
	)
	(segment
		(start 311.265062 -276.46122)
		(end 310.626252 -277.10003)
		(width 0.18288)
		(layer "In2.Cu")
		(net "M_B_CPU0_SA_CB<3>")
	)
	(segment
		(start 304.089054 -276.29485)
		(end 303.929034 -276.13483)
		(width 0.18288)
		(layer "In2.Cu")
		(net "M_B_CPU0_SA_CB<3>")
	)
	(segment
		(start 309.8165 -276.84349)
		(end 308.002432 -276.84349)
		(width 0.18288)
		(layer "In2.Cu")
		(net "M_B_CPU0_SA_CB<3>")
	)
	(segment
		(start 311.987946 -274.4597)
		(end 311.987946 -274.90293)
		(width 0.18288)
		(layer "In2.Cu")
		(net "M_B_CPU0_SA_CB<3>")
	)
	(segment
		(start 335.926684 -261.561072)
		(end 335.91246 -261.5692)
		(width 0.088646)
		(layer "In2.Cu")
		(net "M_B_CPU0_SA_CB<3>")
	)
	(segment
		(start 303.20869 -277.093426)
		(end 302.495204 -277.093426)
		(width 0.18288)
		(layer "In2.Cu")
		(net "M_B_CPU0_SA_CB<3>")
	)
	(segment
		(start 310.626252 -277.10003)
		(end 310.07304 -277.10003)
		(width 0.18288)
		(layer "In2.Cu")
		(net "M_B_CPU0_SA_CB<3>")
	)
	(segment
		(start 315.785246 -273.275298)
		(end 315.785246 -273.662394)
		(width 0.18288)
		(layer "In2.Cu")
		(net "M_B_CPU0_SA_CB<3>")
	)
	(segment
		(start 317.084456 -271.976088)
		(end 316.780418 -272.280126)
		(width 0.18288)
		(layer "In2.Cu")
		(net "M_B_CPU0_SA_CB<3>")
	)
	(segment
		(start 321.45224 -267.9954)
		(end 321.065144 -267.9954)
		(width 0.18288)
		(layer "In2.Cu")
		(net "M_B_CPU0_SA_CB<3>")
	)
	(segment
		(start 317.77559 -271.284954)
		(end 317.77559 -271.67205)
		(width 0.18288)
		(layer "In2.Cu")
		(net "M_B_CPU0_SA_CB<3>")
	)
	(segment
		(start 315.481208 -273.966432)
		(end 315.094112 -273.966432)
		(width 0.18288)
		(layer "In2.Cu")
		(net "M_B_CPU0_SA_CB<3>")
	)
	(segment
		(start 322.75145 -266.309094)
		(end 322.75145 -266.69619)
		(width 0.18288)
		(layer "In2.Cu")
		(net "M_B_CPU0_SA_CB<3>")
	)
	(segment
		(start 311.109106 -276.02561)
		(end 311.265062 -276.181566)
		(width 0.18288)
		(layer "In2.Cu")
		(net "M_B_CPU0_SA_CB<3>")
	)
	(segment
		(start 304.237136 -276.760432)
		(end 304.089054 -276.61235)
		(width 0.18288)
		(layer "In2.Cu")
		(net "M_B_CPU0_SA_CB<3>")
	)
	(segment
		(start 316.780418 -272.280126)
		(end 316.780418 -272.667222)
		(width 0.18288)
		(layer "In2.Cu")
		(net "M_B_CPU0_SA_CB<3>")
	)
	(segment
		(start 314.793884 -274.26666)
		(end 312.180986 -274.26666)
		(width 0.18288)
		(layer "In2.Cu")
		(net "M_B_CPU0_SA_CB<3>")
	)
	(segment
		(start 302.219868 -276.81809)
		(end 300.484032 -276.81809)
		(width 0.18288)
		(layer "In2.Cu")
		(net "M_B_CPU0_SA_CB<3>")
	)
	(segment
		(start 338.144866 -261.235952)
		(end 337.892136 -260.983222)
		(width 0.088646)
		(layer "In2.Cu")
		(net "M_B_CPU0_SA_CB<3>")
	)
	(segment
		(start 315.094112 -273.966432)
		(end 314.793884 -274.26666)
		(width 0.18288)
		(layer "In2.Cu")
		(net "M_B_CPU0_SA_CB<3>")
	)
	(segment
		(start 320.761106 -268.686534)
		(end 320.457068 -268.990572)
		(width 0.18288)
		(layer "In2.Cu")
		(net "M_B_CPU0_SA_CB<3>")
	)
	(segment
		(start 307.360574 -277.065232)
		(end 306.847494 -276.552152)
		(width 0.18288)
		(layer "In2.Cu")
		(net "M_B_CPU0_SA_CB<3>")
	)
	(segment
		(start 320.457068 -268.990572)
		(end 320.069972 -268.990572)
		(width 0.18288)
		(layer "In2.Cu")
		(net "M_B_CPU0_SA_CB<3>")
	)
	(segment
		(start 315.785246 -273.662394)
		(end 315.481208 -273.966432)
		(width 0.18288)
		(layer "In2.Cu")
		(net "M_B_CPU0_SA_CB<3>")
	)
	(segment
		(start 312.180986 -274.26666)
		(end 311.987946 -274.4597)
		(width 0.18288)
		(layer "In2.Cu")
		(net "M_B_CPU0_SA_CB<3>")
	)
	(segment
		(start 316.47638 -272.97126)
		(end 316.089284 -272.97126)
		(width 0.18288)
		(layer "In2.Cu")
		(net "M_B_CPU0_SA_CB<3>")
	)
	(segment
		(start 319.765934 -269.681706)
		(end 319.461896 -269.985744)
		(width 0.18288)
		(layer "In2.Cu")
		(net "M_B_CPU0_SA_CB<3>")
	)
	(segment
		(start 329.174856 -263.364726)
		(end 327.374504 -263.364726)
		(width 0.18288)
		(layer "In2.Cu")
		(net "M_B_CPU0_SA_CB<3>")
	)
	(segment
		(start 327.374504 -263.364726)
		(end 325.903082 -264.836148)
		(width 0.18288)
		(layer "In2.Cu")
		(net "M_B_CPU0_SA_CB<3>")
	)
	(segment
		(start 318.770762 -270.289782)
		(end 318.770762 -270.676878)
		(width 0.18288)
		(layer "In2.Cu")
		(net "M_B_CPU0_SA_CB<3>")
	)
	(segment
		(start 329.671172 -263.364726)
		(end 329.174856 -263.364726)
		(width 0.088646)
		(layer "In2.Cu")
		(net "M_B_CPU0_SA_CB<3>")
	)
	(segment
		(start 317.77559 -271.67205)
		(end 317.471552 -271.976088)
		(width 0.18288)
		(layer "In2.Cu")
		(net "M_B_CPU0_SA_CB<3>")
	)
	(segment
		(start 319.765934 -269.29461)
		(end 319.765934 -269.681706)
		(width 0.18288)
		(layer "In2.Cu")
		(net "M_B_CPU0_SA_CB<3>")
	)
	(segment
		(start 311.109106 -275.326094)
		(end 311.109106 -276.02561)
		(width 0.18288)
		(layer "In2.Cu")
		(net "M_B_CPU0_SA_CB<3>")
	)
	(segment
		(start 338.544408 -261.245096)
		(end 338.167218 -261.245096)
		(width 0.088646)
		(layer "In2.Cu")
		(net "M_B_CPU0_SA_CB<3>")
	)
	(segment
		(start 307.78069 -277.065232)
		(end 307.360574 -277.065232)
		(width 0.18288)
		(layer "In2.Cu")
		(net "M_B_CPU0_SA_CB<3>")
	)
	(segment
		(start 310.07304 -277.10003)
		(end 309.8165 -276.84349)
		(width 0.18288)
		(layer "In2.Cu")
		(net "M_B_CPU0_SA_CB<3>")
	)
	(segment
		(start 319.0748 -269.985744)
		(end 318.770762 -270.289782)
		(width 0.18288)
		(layer "In2.Cu")
		(net "M_B_CPU0_SA_CB<3>")
	)
	(segment
		(start 304.089054 -276.61235)
		(end 304.089054 -276.29485)
		(width 0.18288)
		(layer "In2.Cu")
		(net "M_B_CPU0_SA_CB<3>")
	)
	(segment
		(start 318.770762 -270.676878)
		(end 318.466724 -270.980916)
		(width 0.18288)
		(layer "In2.Cu")
		(net "M_B_CPU0_SA_CB<3>")
	)
	(segment
		(start 300.484032 -276.81809)
		(end 300.298866 -277.003256)
		(width 0.18288)
		(layer "In2.Cu")
		(net "M_B_CPU0_SA_CB<3>")
	)
	(segment
		(start 318.466724 -270.980916)
		(end 318.079628 -270.980916)
		(width 0.18288)
		(layer "In2.Cu")
		(net "M_B_CPU0_SA_CB<3>")
	)
	(segment
		(start 304.962306 -277.128224)
		(end 304.594514 -276.760432)
		(width 0.18288)
		(layer "In2.Cu")
		(net "M_B_CPU0_SA_CB<3>")
	)
	(segment
		(start 300.298866 -277.003256)
		(end 299.666152 -277.003256)
		(width 0.18288)
		(layer "In2.Cu")
		(net "M_B_CPU0_SA_CB<3>")
	)
	(segment
		(start 318.079628 -270.980916)
		(end 317.77559 -271.284954)
		(width 0.18288)
		(layer "In2.Cu")
		(net "M_B_CPU0_SA_CB<3>")
	)
	(segment
		(start 322.447412 -267.000228)
		(end 322.060316 -267.000228)
		(width 0.18288)
		(layer "In2.Cu")
		(net "M_B_CPU0_SA_CB<3>")
	)
	(segment
		(start 305.998118 -277.128224)
		(end 304.962306 -277.128224)
		(width 0.18288)
		(layer "In2.Cu")
		(net "M_B_CPU0_SA_CB<3>")
	)
	(segment
		(start 320.761106 -268.299438)
		(end 320.761106 -268.686534)
		(width 0.18288)
		(layer "In2.Cu")
		(net "M_B_CPU0_SA_CB<3>")
	)
	(segment
		(start 306.57419 -276.552152)
		(end 305.998118 -277.128224)
		(width 0.18288)
		(layer "In2.Cu")
		(net "M_B_CPU0_SA_CB<3>")
	)
	(segment
		(start 302.495204 -277.093426)
		(end 302.219868 -276.81809)
		(width 0.18288)
		(layer "In2.Cu")
		(net "M_B_CPU0_SA_CB<3>")
	)
	(segment
		(start 304.594514 -276.760432)
		(end 304.237136 -276.760432)
		(width 0.18288)
		(layer "In2.Cu")
		(net "M_B_CPU0_SA_CB<3>")
	)
	(segment
		(start 311.987946 -274.90293)
		(end 311.792874 -275.098002)
		(width 0.18288)
		(layer "In2.Cu")
		(net "M_B_CPU0_SA_CB<3>")
	)
	(segment
		(start 338.544662 -261.244842)
		(end 338.544408 -261.245096)
		(width 0.088646)
		(layer "In2.Cu")
		(net "M_B_CPU0_SA_CB<3>")
	)
	(segment
		(start 306.847494 -276.552152)
		(end 306.57419 -276.552152)
		(width 0.18288)
		(layer "In2.Cu")
		(net "M_B_CPU0_SA_CB<3>")
	)
	(segment
		(start 311.265062 -276.181566)
		(end 311.265062 -276.46122)
		(width 0.18288)
		(layer "In2.Cu")
		(net "M_B_CPU0_SA_CB<3>")
	)
	(segment
		(start 331.966062 -261.619746)
		(end 331.416152 -261.619746)
		(width 0.088646)
		(layer "In2.Cu")
		(net "M_B_CPU0_SA_CB<3>")
	)
	(segment
		(start 322.75145 -266.69619)
		(end 322.447412 -267.000228)
		(width 0.18288)
		(layer "In2.Cu")
		(net "M_B_CPU0_SA_CB<3>")
	)
	(segment
		(start 325.903082 -264.836148)
		(end 323.037454 -266.02309)
		(width 0.18288)
		(layer "In2.Cu")
		(net "M_B_CPU0_SA_CB<3>")
	)
	(segment
		(start 322.060316 -267.000228)
		(end 321.756278 -267.304266)
		(width 0.18288)
		(layer "In2.Cu")
		(net "M_B_CPU0_SA_CB<3>")
	)
	(segment
		(start 311.337198 -275.098002)
		(end 311.109106 -275.326094)
		(width 0.18288)
		(layer "In2.Cu")
		(net "M_B_CPU0_SA_CB<3>")
	)
	(segment
		(start 303.929034 -276.13483)
		(end 303.56175 -276.13483)
		(width 0.18288)
		(layer "In2.Cu")
		(net "M_B_CPU0_SA_CB<3>")
	)
	(segment
		(start 323.037454 -266.02309)
		(end 322.75145 -266.309094)
		(width 0.18288)
		(layer "In2.Cu")
		(net "M_B_CPU0_SA_CB<3>")
	)
	(segment
		(start 316.089284 -272.97126)
		(end 315.785246 -273.275298)
		(width 0.18288)
		(layer "In2.Cu")
		(net "M_B_CPU0_SA_CB<3>")
	)
	(segment
		(start 303.36871 -276.933406)
		(end 303.20869 -277.093426)
		(width 0.18288)
		(layer "In2.Cu")
		(net "M_B_CPU0_SA_CB<3>")
	)
	(segment
		(start 319.461896 -269.985744)
		(end 319.0748 -269.985744)
		(width 0.18288)
		(layer "In2.Cu")
		(net "M_B_CPU0_SA_CB<3>")
	)
	(segment
		(start 321.756278 -267.304266)
		(end 321.756278 -267.691362)
		(width 0.18288)
		(layer "In2.Cu")
		(net "M_B_CPU0_SA_CB<3>")
	)
	(segment
		(start 321.756278 -267.691362)
		(end 321.45224 -267.9954)
		(width 0.18288)
		(layer "In2.Cu")
		(net "M_B_CPU0_SA_CB<3>")
	)
	(segment
		(start 320.069972 -268.990572)
		(end 319.765934 -269.29461)
		(width 0.18288)
		(layer "In2.Cu")
		(net "M_B_CPU0_SA_CB<3>")
	)
	(segment
		(start 311.792874 -275.098002)
		(end 311.337198 -275.098002)
		(width 0.18288)
		(layer "In2.Cu")
		(net "M_B_CPU0_SA_CB<3>")
	)
	(segment
		(start 321.065144 -267.9954)
		(end 320.761106 -268.299438)
		(width 0.18288)
		(layer "In2.Cu")
		(net "M_B_CPU0_SA_CB<3>")
	)
	(segment
		(start 331.416152 -261.619746)
		(end 329.671172 -263.364726)
		(width 0.088646)
		(layer "In2.Cu")
		(net "M_B_CPU0_SA_CB<3>")
	)
	(segment
		(start 317.471552 -271.976088)
		(end 317.084456 -271.976088)
		(width 0.18288)
		(layer "In2.Cu")
		(net "M_B_CPU0_SA_CB<3>")
	)
	(segment
		(start 308.002432 -276.84349)
		(end 307.78069 -277.065232)
		(width 0.18288)
		(layer "In2.Cu")
		(net "M_B_CPU0_SA_CB<3>")
	)
	(segment
		(start 316.780418 -272.667222)
		(end 316.47638 -272.97126)
		(width 0.18288)
		(layer "In2.Cu")
		(net "M_B_CPU0_SA_CB<3>")
	)
	(segment
		(start 303.36871 -276.32787)
		(end 303.36871 -276.933406)
		(width 0.18288)
		(layer "In2.Cu")
		(net "M_B_CPU0_SA_CB<3>")
	)
	(segment
		(start 336.244184 -260.994398)
		(end 336.203544 -261.015988)
		(width 0.088646)
		(layer "In2.Cu")
		(net "M_B_CPU0_SA_CB<3>")
	)
	(arc
		(start 336.099912 -261.245096)
		(mid 336.053773 -261.425281)
		(end 335.926684 -261.561072)
		(width 0.088646)
		(layer "In2.Cu")
		(net "M_B_CPU0_SA_CB<3>")
	)
	(arc
		(start 337.351116 -260.947408)
		(mid 337.13511 -260.983136)
		(end 336.919062 -260.947662)
		(width 0.088646)
		(layer "In2.Cu")
		(net "M_B_CPU0_SA_CB<3>")
	)
	(arc
		(start 333.658464 -261.5692)
		(mid 333.375762 -261.493424)
		(end 333.09306 -261.5692)
		(width 0.088646)
		(layer "In2.Cu")
		(net "M_B_CPU0_SA_CB<3>")
	)
	(arc
		(start 336.203544 -261.015988)
		(mid 336.127021 -261.119367)
		(end 336.099912 -261.245096)
		(width 0.088646)
		(layer "In2.Cu")
		(net "M_B_CPU0_SA_CB<3>")
	)
	(arc
		(start 338.167218 -261.245096)
		(mid 338.155165 -261.242699)
		(end 338.144866 -261.235952)
		(width 0.088646)
		(layer "In2.Cu")
		(net "M_B_CPU0_SA_CB<3>")
	)
	(arc
		(start 334.03286 -261.5692)
		(mid 333.845662 -261.619377)
		(end 333.658464 -261.5692)
		(width 0.088646)
		(layer "In2.Cu")
		(net "M_B_CPU0_SA_CB<3>")
	)
	(arc
		(start 334.598264 -261.5692)
		(mid 334.315562 -261.493424)
		(end 334.03286 -261.5692)
		(width 0.088646)
		(layer "In2.Cu")
		(net "M_B_CPU0_SA_CB<3>")
	)
	(arc
		(start 336.919062 -260.947662)
		(mid 336.877755 -260.931683)
		(end 336.837782 -260.91261)
		(width 0.088646)
		(layer "In2.Cu")
		(net "M_B_CPU0_SA_CB<3>")
	)
	(arc
		(start 332.15326 -261.5692)
		(mid 332.062984 -261.606774)
		(end 331.966062 -261.619746)
		(width 0.088646)
		(layer "In2.Cu")
		(net "M_B_CPU0_SA_CB<3>")
	)
	(arc
		(start 335.91246 -261.5692)
		(mid 335.725262 -261.619377)
		(end 335.538064 -261.5692)
		(width 0.088646)
		(layer "In2.Cu")
		(net "M_B_CPU0_SA_CB<3>")
	)
	(arc
		(start 334.97266 -261.5692)
		(mid 334.785462 -261.619377)
		(end 334.598264 -261.5692)
		(width 0.088646)
		(layer "In2.Cu")
		(net "M_B_CPU0_SA_CB<3>")
	)
	(arc
		(start 337.892136 -260.983222)
		(mid 337.673874 -260.872527)
		(end 337.432396 -260.912356)
		(width 0.088646)
		(layer "In2.Cu")
		(net "M_B_CPU0_SA_CB<3>")
	)
	(arc
		(start 335.538064 -261.5692)
		(mid 335.255362 -261.493424)
		(end 334.97266 -261.5692)
		(width 0.088646)
		(layer "In2.Cu")
		(net "M_B_CPU0_SA_CB<3>")
	)
	(arc
		(start 337.432396 -260.912356)
		(mid 337.392427 -260.931437)
		(end 337.351116 -260.947408)
		(width 0.088646)
		(layer "In2.Cu")
		(net "M_B_CPU0_SA_CB<3>")
	)
	(arc
		(start 333.09306 -261.5692)
		(mid 332.905862 -261.619343)
		(end 332.718664 -261.5692)
		(width 0.088646)
		(layer "In2.Cu")
		(net "M_B_CPU0_SA_CB<3>")
	)
	(arc
		(start 332.718664 -261.5692)
		(mid 332.435962 -261.493424)
		(end 332.15326 -261.5692)
		(width 0.088646)
		(layer "In2.Cu")
		(net "M_B_CPU0_SA_CB<3>")
	)
	(arc
		(start 336.837782 -260.91261)
		(mid 336.656793 -260.870638)
		(end 336.477864 -260.920738)
		(width 0.088646)
		(layer "In2.Cu")
		(net "M_B_CPU0_SA_CB<3>")
	)
	(arc
		(start 336.477864 -260.920738)
		(mid 336.365057 -260.970353)
		(end 336.244184 -260.994398)
		(width 0.088646)
		(layer "In2.Cu")
		(net "M_B_CPU0_SA_CB<3>")
	)
	(segment
		(start 291.937948 -277.631652)
		(end 292.67531 -277.631652)
		(width 0.20066)
		(layer "F.Cu")
		(net "M_B_CPU0_SA_CB<2>")
	)
	(segment
		(start 296.373042 -278.27859)
		(end 296.584878 -278.066754)
		(width 0.20066)
		(layer "F.Cu")
		(net "M_B_CPU0_SA_CB<2>")
	)
	(segment
		(start 295.944544 -278.27859)
		(end 296.373042 -278.27859)
		(width 0.20066)
		(layer "F.Cu")
		(net "M_B_CPU0_SA_CB<2>")
	)
	(segment
		(start 291.502846 -278.066754)
		(end 291.937948 -277.631652)
		(width 0.20066)
		(layer "F.Cu")
		(net "M_B_CPU0_SA_CB<2>")
	)
	(segment
		(start 292.68547 -277.641812)
		(end 292.940486 -277.641812)
		(width 0.101854)
		(layer "F.Cu")
		(net "M_B_CPU0_SA_CB<2>")
	)
	(segment
		(start 338.074762 -261.522718)
		(end 338.074762 -262.058658)
		(width 0.20066)
		(layer "F.Cu")
		(net "M_B_CPU0_SA_CB<2>")
	)
	(segment
		(start 295.633394 -277.641812)
		(end 295.777158 -277.785576)
		(width 0.20066)
		(layer "F.Cu")
		(net "M_B_CPU0_SA_CB<2>")
	)
	(segment
		(start 299.029628 -278.066754)
		(end 297.899582 -278.066754)
		(width 0.20066)
		(layer "F.Cu")
		(net "M_B_CPU0_SA_CB<2>")
	)
	(segment
		(start 292.67531 -277.631652)
		(end 292.68547 -277.641812)
		(width 0.101854)
		(layer "F.Cu")
		(net "M_B_CPU0_SA_CB<2>")
	)
	(segment
		(start 290.355782 -278.066754)
		(end 291.502846 -278.066754)
		(width 0.20066)
		(layer "F.Cu")
		(net "M_B_CPU0_SA_CB<2>")
	)
	(segment
		(start 292.940486 -277.641812)
		(end 295.000426 -277.641812)
		(width 0.1016)
		(layer "F.Cu")
		(net "M_B_CPU0_SA_CB<2>")
	)
	(segment
		(start 299.029882 -278.067008)
		(end 299.029628 -278.066754)
		(width 0.20066)
		(layer "F.Cu")
		(net "M_B_CPU0_SA_CB<2>")
	)
	(segment
		(start 295.777158 -278.111204)
		(end 295.944544 -278.27859)
		(width 0.20066)
		(layer "F.Cu")
		(net "M_B_CPU0_SA_CB<2>")
	)
	(segment
		(start 295.777158 -277.785576)
		(end 295.777158 -278.111204)
		(width 0.20066)
		(layer "F.Cu")
		(net "M_B_CPU0_SA_CB<2>")
	)
	(segment
		(start 296.584878 -278.066754)
		(end 297.899582 -278.066754)
		(width 0.20066)
		(layer "F.Cu")
		(net "M_B_CPU0_SA_CB<2>")
	)
	(segment
		(start 295.000426 -277.641812)
		(end 295.633394 -277.641812)
		(width 0.20066)
		(layer "F.Cu")
		(net "M_B_CPU0_SA_CB<2>")
	)
	(segment
		(start 299.976794 -279.275032)
		(end 299.768006 -279.066244)
		(width 0.18288)
		(layer "In2.Cu")
		(net "M_B_CPU0_SA_CB<2>")
	)
	(segment
		(start 303.518062 -279.483312)
		(end 303.309782 -279.691592)
		(width 0.18288)
		(layer "In2.Cu")
		(net "M_B_CPU0_SA_CB<2>")
	)
	(segment
		(start 300.321218 -279.275032)
		(end 299.976794 -279.275032)
		(width 0.18288)
		(layer "In2.Cu")
		(net "M_B_CPU0_SA_CB<2>")
	)
	(segment
		(start 300.477936 -279.118314)
		(end 300.321218 -279.275032)
		(width 0.18288)
		(layer "In2.Cu")
		(net "M_B_CPU0_SA_CB<2>")
	)
	(segment
		(start 302.814482 -278.775668)
		(end 302.601884 -278.56307)
		(width 0.18288)
		(layer "In2.Cu")
		(net "M_B_CPU0_SA_CB<2>")
	)
	(segment
		(start 312.31713 -277.443438)
		(end 311.968134 -277.792434)
		(width 0.18288)
		(layer "In2.Cu")
		(net "M_B_CPU0_SA_CB<2>")
	)
	(segment
		(start 330.36256 -263.57199)
		(end 330.252832 -263.57199)
		(width 0.088646)
		(layer "In2.Cu")
		(net "M_B_CPU0_SA_CB<2>")
	)
	(segment
		(start 299.223684 -278.26081)
		(end 299.029882 -278.067008)
		(width 0.18288)
		(layer "In2.Cu")
		(net "M_B_CPU0_SA_CB<2>")
	)
	(segment
		(start 328.144378 -264.055606)
		(end 326.518778 -265.681206)
		(width 0.18288)
		(layer "In2.Cu")
		(net "M_B_CPU0_SA_CB<2>")
	)
	(segment
		(start 311.968134 -277.792434)
		(end 310.223408 -278.515572)
		(width 0.18288)
		(layer "In2.Cu")
		(net "M_B_CPU0_SA_CB<2>")
	)
	(segment
		(start 312.838846 -276.789896)
		(end 312.553604 -276.789896)
		(width 0.18288)
		(layer "In2.Cu")
		(net "M_B_CPU0_SA_CB<2>")
	)
	(segment
		(start 309.733696 -278.515572)
		(end 309.34025 -278.122126)
		(width 0.18288)
		(layer "In2.Cu")
		(net "M_B_CPU0_SA_CB<2>")
	)
	(segment
		(start 337.417664 -261.5692)
		(end 337.402932 -261.560564)
		(width 0.088646)
		(layer "In2.Cu")
		(net "M_B_CPU0_SA_CB<2>")
	)
	(segment
		(start 314.512706 -275.603716)
		(end 314.512706 -275.876512)
		(width 0.18288)
		(layer "In2.Cu")
		(net "M_B_CPU0_SA_CB<2>")
	)
	(segment
		(start 314.624212 -275.988018)
		(end 314.624212 -276.260814)
		(width 0.18288)
		(layer "In2.Cu")
		(net "M_B_CPU0_SA_CB<2>")
	)
	(segment
		(start 313.131454 -277.082504)
		(end 312.838846 -276.789896)
		(width 0.18288)
		(layer "In2.Cu")
		(net "M_B_CPU0_SA_CB<2>")
	)
	(segment
		(start 324.273926 -266.6111)
		(end 315.394594 -275.490432)
		(width 0.18288)
		(layer "In2.Cu")
		(net "M_B_CPU0_SA_CB<2>")
	)
	(segment
		(start 299.768006 -279.066244)
		(end 299.768006 -278.45385)
		(width 0.18288)
		(layer "In2.Cu")
		(net "M_B_CPU0_SA_CB<2>")
	)
	(segment
		(start 329.769216 -264.055606)
		(end 329.174856 -264.055606)
		(width 0.088646)
		(layer "In2.Cu")
		(net "M_B_CPU0_SA_CB<2>")
	)
	(segment
		(start 336.39125 -262.377936)
		(end 336.38236 -262.383016)
		(width 0.088646)
		(layer "In2.Cu")
		(net "M_B_CPU0_SA_CB<2>")
	)
	(segment
		(start 314.09513 -276.789896)
		(end 313.697366 -276.789896)
		(width 0.18288)
		(layer "In2.Cu")
		(net "M_B_CPU0_SA_CB<2>")
	)
	(segment
		(start 302.601884 -278.56307)
		(end 302.236378 -278.56307)
		(width 0.18288)
		(layer "In2.Cu")
		(net "M_B_CPU0_SA_CB<2>")
	)
	(segment
		(start 331.627226 -262.307324)
		(end 330.36256 -263.57199)
		(width 0.088646)
		(layer "In2.Cu")
		(net "M_B_CPU0_SA_CB<2>")
	)
	(segment
		(start 303.309782 -279.691592)
		(end 303.007522 -279.691592)
		(width 0.18288)
		(layer "In2.Cu")
		(net "M_B_CPU0_SA_CB<2>")
	)
	(segment
		(start 299.768006 -278.45385)
		(end 299.574966 -278.26081)
		(width 0.18288)
		(layer "In2.Cu")
		(net "M_B_CPU0_SA_CB<2>")
	)
	(segment
		(start 309.34025 -278.122126)
		(end 308.365398 -278.122126)
		(width 0.18288)
		(layer "In2.Cu")
		(net "M_B_CPU0_SA_CB<2>")
	)
	(segment
		(start 304.470562 -278.44496)
		(end 303.73066 -278.44496)
		(width 0.18288)
		(layer "In2.Cu")
		(net "M_B_CPU0_SA_CB<2>")
	)
	(segment
		(start 306.315618 -278.467312)
		(end 305.93792 -278.84501)
		(width 0.18288)
		(layer "In2.Cu")
		(net "M_B_CPU0_SA_CB<2>")
	)
	(segment
		(start 315.121798 -275.490432)
		(end 315.010292 -275.378926)
		(width 0.18288)
		(layer "In2.Cu")
		(net "M_B_CPU0_SA_CB<2>")
	)
	(segment
		(start 303.73066 -278.44496)
		(end 303.518062 -278.657558)
		(width 0.18288)
		(layer "In2.Cu")
		(net "M_B_CPU0_SA_CB<2>")
	)
	(segment
		(start 304.870612 -278.84501)
		(end 304.470562 -278.44496)
		(width 0.18288)
		(layer "In2.Cu")
		(net "M_B_CPU0_SA_CB<2>")
	)
	(segment
		(start 310.223408 -278.515572)
		(end 309.733696 -278.515572)
		(width 0.18288)
		(layer "In2.Cu")
		(net "M_B_CPU0_SA_CB<2>")
	)
	(segment
		(start 315.010292 -275.378926)
		(end 314.737496 -275.378926)
		(width 0.18288)
		(layer "In2.Cu")
		(net "M_B_CPU0_SA_CB<2>")
	)
	(segment
		(start 313.404758 -277.082504)
		(end 313.131454 -277.082504)
		(width 0.18288)
		(layer "In2.Cu")
		(net "M_B_CPU0_SA_CB<2>")
	)
	(segment
		(start 300.477936 -278.495506)
		(end 300.477936 -279.118314)
		(width 0.18288)
		(layer "In2.Cu")
		(net "M_B_CPU0_SA_CB<2>")
	)
	(segment
		(start 314.512706 -275.876512)
		(end 314.624212 -275.988018)
		(width 0.18288)
		(layer "In2.Cu")
		(net "M_B_CPU0_SA_CB<2>")
	)
	(segment
		(start 307.665374 -278.82215)
		(end 307.37683 -278.82215)
		(width 0.18288)
		(layer "In2.Cu")
		(net "M_B_CPU0_SA_CB<2>")
	)
	(segment
		(start 337.42376 -261.572756)
		(end 337.417664 -261.5692)
		(width 0.088646)
		(layer "In2.Cu")
		(net "M_B_CPU0_SA_CB<2>")
	)
	(segment
		(start 338.074762 -262.058658)
		(end 337.762088 -262.058658)
		(width 0.088646)
		(layer "In2.Cu")
		(net "M_B_CPU0_SA_CB<2>")
	)
	(segment
		(start 312.553604 -276.789896)
		(end 312.31713 -277.02637)
		(width 0.18288)
		(layer "In2.Cu")
		(net "M_B_CPU0_SA_CB<2>")
	)
	(segment
		(start 315.394594 -275.490432)
		(end 315.121798 -275.490432)
		(width 0.18288)
		(layer "In2.Cu")
		(net "M_B_CPU0_SA_CB<2>")
	)
	(segment
		(start 305.93792 -278.84501)
		(end 304.870612 -278.84501)
		(width 0.18288)
		(layer "In2.Cu")
		(net "M_B_CPU0_SA_CB<2>")
	)
	(segment
		(start 336.85226 -261.5692)
		(end 336.846164 -261.572756)
		(width 0.088646)
		(layer "In2.Cu")
		(net "M_B_CPU0_SA_CB<2>")
	)
	(segment
		(start 302.236378 -278.56307)
		(end 301.97171 -278.298402)
		(width 0.18288)
		(layer "In2.Cu")
		(net "M_B_CPU0_SA_CB<2>")
	)
	(segment
		(start 331.966062 -262.307324)
		(end 331.627226 -262.307324)
		(width 0.088646)
		(layer "In2.Cu")
		(net "M_B_CPU0_SA_CB<2>")
	)
	(segment
		(start 299.574966 -278.26081)
		(end 299.223684 -278.26081)
		(width 0.18288)
		(layer "In2.Cu")
		(net "M_B_CPU0_SA_CB<2>")
	)
	(segment
		(start 300.67504 -278.298402)
		(end 300.477936 -278.495506)
		(width 0.18288)
		(layer "In2.Cu")
		(net "M_B_CPU0_SA_CB<2>")
	)
	(segment
		(start 326.518778 -265.681206)
		(end 324.273926 -266.6111)
		(width 0.18288)
		(layer "In2.Cu")
		(net "M_B_CPU0_SA_CB<2>")
	)
	(segment
		(start 330.252832 -263.57199)
		(end 329.769216 -264.055606)
		(width 0.088646)
		(layer "In2.Cu")
		(net "M_B_CPU0_SA_CB<2>")
	)
	(segment
		(start 302.814482 -279.498552)
		(end 302.814482 -278.775668)
		(width 0.18288)
		(layer "In2.Cu")
		(net "M_B_CPU0_SA_CB<2>")
	)
	(segment
		(start 337.762088 -262.058658)
		(end 337.696556 -261.993126)
		(width 0.088646)
		(layer "In2.Cu")
		(net "M_B_CPU0_SA_CB<2>")
	)
	(segment
		(start 308.365398 -278.122126)
		(end 307.665374 -278.82215)
		(width 0.18288)
		(layer "In2.Cu")
		(net "M_B_CPU0_SA_CB<2>")
	)
	(segment
		(start 313.697366 -276.789896)
		(end 313.404758 -277.082504)
		(width 0.18288)
		(layer "In2.Cu")
		(net "M_B_CPU0_SA_CB<2>")
	)
	(segment
		(start 307.37683 -278.82215)
		(end 307.021992 -278.467312)
		(width 0.18288)
		(layer "In2.Cu")
		(net "M_B_CPU0_SA_CB<2>")
	)
	(segment
		(start 307.021992 -278.467312)
		(end 306.315618 -278.467312)
		(width 0.18288)
		(layer "In2.Cu")
		(net "M_B_CPU0_SA_CB<2>")
	)
	(segment
		(start 314.737496 -275.378926)
		(end 314.512706 -275.603716)
		(width 0.18288)
		(layer "In2.Cu")
		(net "M_B_CPU0_SA_CB<2>")
	)
	(segment
		(start 314.624212 -276.260814)
		(end 314.09513 -276.789896)
		(width 0.18288)
		(layer "In2.Cu")
		(net "M_B_CPU0_SA_CB<2>")
	)
	(segment
		(start 303.007522 -279.691592)
		(end 302.814482 -279.498552)
		(width 0.18288)
		(layer "In2.Cu")
		(net "M_B_CPU0_SA_CB<2>")
	)
	(segment
		(start 301.97171 -278.298402)
		(end 300.67504 -278.298402)
		(width 0.18288)
		(layer "In2.Cu")
		(net "M_B_CPU0_SA_CB<2>")
	)
	(segment
		(start 312.31713 -277.02637)
		(end 312.31713 -277.443438)
		(width 0.18288)
		(layer "In2.Cu")
		(net "M_B_CPU0_SA_CB<2>")
	)
	(segment
		(start 303.518062 -278.657558)
		(end 303.518062 -279.483312)
		(width 0.18288)
		(layer "In2.Cu")
		(net "M_B_CPU0_SA_CB<2>")
	)
	(segment
		(start 329.174856 -264.055606)
		(end 328.144378 -264.055606)
		(width 0.18288)
		(layer "In2.Cu")
		(net "M_B_CPU0_SA_CB<2>")
	)
	(arc
		(start 333.188564 -262.383016)
		(mid 332.905862 -262.30724)
		(end 332.62316 -262.383016)
		(width 0.088646)
		(layer "In2.Cu")
		(net "M_B_CPU0_SA_CB<2>")
	)
	(arc
		(start 336.38236 -262.383016)
		(mid 336.195162 -262.433159)
		(end 336.007964 -262.383016)
		(width 0.088646)
		(layer "In2.Cu")
		(net "M_B_CPU0_SA_CB<2>")
	)
	(arc
		(start 332.248764 -262.383016)
		(mid 332.112398 -262.326538)
		(end 331.966062 -262.307324)
		(width 0.088646)
		(layer "In2.Cu")
		(net "M_B_CPU0_SA_CB<2>")
	)
	(arc
		(start 337.402932 -261.560564)
		(mid 337.126457 -261.493244)
		(end 336.85226 -261.5692)
		(width 0.088646)
		(layer "In2.Cu")
		(net "M_B_CPU0_SA_CB<2>")
	)
	(arc
		(start 335.44256 -262.383016)
		(mid 335.255362 -262.433159)
		(end 335.068164 -262.383016)
		(width 0.088646)
		(layer "In2.Cu")
		(net "M_B_CPU0_SA_CB<2>")
	)
	(arc
		(start 332.62316 -262.383016)
		(mid 332.435962 -262.433159)
		(end 332.248764 -262.383016)
		(width 0.088646)
		(layer "In2.Cu")
		(net "M_B_CPU0_SA_CB<2>")
	)
	(arc
		(start 333.56296 -262.383016)
		(mid 333.375762 -262.433159)
		(end 333.188564 -262.383016)
		(width 0.088646)
		(layer "In2.Cu")
		(net "M_B_CPU0_SA_CB<2>")
	)
	(arc
		(start 336.846164 -261.572756)
		(mid 336.643751 -261.779169)
		(end 336.569812 -262.058658)
		(width 0.088646)
		(layer "In2.Cu")
		(net "M_B_CPU0_SA_CB<2>")
	)
	(arc
		(start 335.068164 -262.383016)
		(mid 334.785462 -262.30724)
		(end 334.50276 -262.383016)
		(width 0.088646)
		(layer "In2.Cu")
		(net "M_B_CPU0_SA_CB<2>")
	)
	(arc
		(start 336.569812 -262.058658)
		(mid 336.522133 -262.241558)
		(end 336.39125 -262.377936)
		(width 0.088646)
		(layer "In2.Cu")
		(net "M_B_CPU0_SA_CB<2>")
	)
	(arc
		(start 336.007964 -262.383016)
		(mid 335.725262 -262.30724)
		(end 335.44256 -262.383016)
		(width 0.088646)
		(layer "In2.Cu")
		(net "M_B_CPU0_SA_CB<2>")
	)
	(arc
		(start 337.696556 -261.993126)
		(mid 337.609312 -261.751038)
		(end 337.42376 -261.572756)
		(width 0.088646)
		(layer "In2.Cu")
		(net "M_B_CPU0_SA_CB<2>")
	)
	(arc
		(start 334.128364 -262.383016)
		(mid 333.845662 -262.30724)
		(end 333.56296 -262.383016)
		(width 0.088646)
		(layer "In2.Cu")
		(net "M_B_CPU0_SA_CB<2>")
	)
	(arc
		(start 334.50276 -262.383016)
		(mid 334.315562 -262.433159)
		(end 334.128364 -262.383016)
		(width 0.088646)
		(layer "In2.Cu")
		(net "M_B_CPU0_SA_CB<2>")
	)
	(segment
		(start 291.225986 -276.791674)
		(end 289.240468 -276.791674)
		(width 0.1016)
		(layer "F.Cu")
		(net "M_B_CPU0_SA_CB<1>")
	)
	(segment
		(start 291.735256 -276.791674)
		(end 291.556694 -276.791674)
		(width 0.20066)
		(layer "F.Cu")
		(net "M_B_CPU0_SA_CB<1>")
	)
	(segment
		(start 288.46018 -276.945344)
		(end 288.46018 -277.273512)
		(width 0.20066)
		(layer "F.Cu")
		(net "M_B_CPU0_SA_CB<1>")
	)
	(segment
		(start 336.665062 -261.244588)
		(end 336.665062 -261.244842)
		(width 0.20066)
		(layer "F.Cu")
		(net "M_B_CPU0_SA_CB<1>")
	)
	(segment
		(start 336.665316 -261.244334)
		(end 336.665062 -261.244588)
		(width 0.20066)
		(layer "F.Cu")
		(net "M_B_CPU0_SA_CB<1>")
	)
	(segment
		(start 294.904414 -277.216616)
		(end 293.799514 -277.216616)
		(width 0.20066)
		(layer "F.Cu")
		(net "M_B_CPU0_SA_CB<1>")
	)
	(segment
		(start 292.160198 -277.216616)
		(end 291.735256 -276.791674)
		(width 0.20066)
		(layer "F.Cu")
		(net "M_B_CPU0_SA_CB<1>")
	)
	(segment
		(start 336.665316 -260.708902)
		(end 336.665316 -261.244334)
		(width 0.20066)
		(layer "F.Cu")
		(net "M_B_CPU0_SA_CB<1>")
	)
	(segment
		(start 288.46018 -277.273512)
		(end 288.305748 -277.427944)
		(width 0.20066)
		(layer "F.Cu")
		(net "M_B_CPU0_SA_CB<1>")
	)
	(segment
		(start 289.231578 -276.782784)
		(end 288.62274 -276.782784)
		(width 0.20066)
		(layer "F.Cu")
		(net "M_B_CPU0_SA_CB<1>")
	)
	(segment
		(start 293.799514 -277.216616)
		(end 292.160198 -277.216616)
		(width 0.20066)
		(layer "F.Cu")
		(net "M_B_CPU0_SA_CB<1>")
	)
	(segment
		(start 287.589976 -277.216616)
		(end 286.255714 -277.216616)
		(width 0.20066)
		(layer "F.Cu")
		(net "M_B_CPU0_SA_CB<1>")
	)
	(segment
		(start 287.801304 -277.427944)
		(end 287.589976 -277.216616)
		(width 0.20066)
		(layer "F.Cu")
		(net "M_B_CPU0_SA_CB<1>")
	)
	(segment
		(start 288.62274 -276.782784)
		(end 288.46018 -276.945344)
		(width 0.20066)
		(layer "F.Cu")
		(net "M_B_CPU0_SA_CB<1>")
	)
	(segment
		(start 289.240468 -276.791674)
		(end 289.231578 -276.782784)
		(width 0.1016)
		(layer "F.Cu")
		(net "M_B_CPU0_SA_CB<1>")
	)
	(segment
		(start 291.556694 -276.791674)
		(end 291.225986 -276.791674)
		(width 0.101854)
		(layer "F.Cu")
		(net "M_B_CPU0_SA_CB<1>")
	)
	(segment
		(start 288.305748 -277.427944)
		(end 287.801304 -277.427944)
		(width 0.20066)
		(layer "F.Cu")
		(net "M_B_CPU0_SA_CB<1>")
	)
	(segment
		(start 323.986144 -266.180316)
		(end 315.3918 -274.77466)
		(width 0.18288)
		(layer "In2.Cu")
		(net "M_B_CPU0_SA_CB<1>")
	)
	(segment
		(start 297.675808 -277.02764)
		(end 297.486324 -277.217124)
		(width 0.18288)
		(layer "In2.Cu")
		(net "M_B_CPU0_SA_CB<1>")
	)
	(segment
		(start 296.607738 -277.929594)
		(end 296.607738 -278.357076)
		(width 0.18288)
		(layer "In2.Cu")
		(net "M_B_CPU0_SA_CB<1>")
	)
	(segment
		(start 327.768966 -263.710166)
		(end 326.227186 -265.251946)
		(width 0.18288)
		(layer "In2.Cu")
		(net "M_B_CPU0_SA_CB<1>")
	)
	(segment
		(start 330.058268 -263.345168)
		(end 329.69327 -263.710166)
		(width 0.088646)
		(layer "In2.Cu")
		(net "M_B_CPU0_SA_CB<1>")
	)
	(segment
		(start 336.665062 -261.244842)
		(end 336.169762 -261.594092)
		(width 0.088646)
		(layer "In2.Cu")
		(net "M_B_CPU0_SA_CB<1>")
	)
	(segment
		(start 330.13269 -263.345168)
		(end 330.058268 -263.345168)
		(width 0.088646)
		(layer "In2.Cu")
		(net "M_B_CPU0_SA_CB<1>")
	)
	(segment
		(start 331.667866 -261.809992)
		(end 330.13269 -263.345168)
		(width 0.088646)
		(layer "In2.Cu")
		(net "M_B_CPU0_SA_CB<1>")
	)
	(segment
		(start 295.582848 -277.216616)
		(end 294.904414 -277.216616)
		(width 0.18288)
		(layer "In2.Cu")
		(net "M_B_CPU0_SA_CB<1>")
	)
	(segment
		(start 315.3918 -274.77466)
		(end 314.11926 -274.77466)
		(width 0.18288)
		(layer "In2.Cu")
		(net "M_B_CPU0_SA_CB<1>")
	)
	(segment
		(start 300.64075 -277.753572)
		(end 300.400974 -277.513796)
		(width 0.18288)
		(layer "In2.Cu")
		(net "M_B_CPU0_SA_CB<1>")
	)
	(segment
		(start 329.174856 -263.710166)
		(end 327.768966 -263.710166)
		(width 0.18288)
		(layer "In2.Cu")
		(net "M_B_CPU0_SA_CB<1>")
	)
	(segment
		(start 310.879744 -277.614126)
		(end 307.410612 -277.614126)
		(width 0.18288)
		(layer "In2.Cu")
		(net "M_B_CPU0_SA_CB<1>")
	)
	(segment
		(start 297.310302 -277.671276)
		(end 296.866056 -277.671276)
		(width 0.18288)
		(layer "In2.Cu")
		(net "M_B_CPU0_SA_CB<1>")
	)
	(segment
		(start 314.11926 -274.77466)
		(end 313.271662 -275.622258)
		(width 0.18288)
		(layer "In2.Cu")
		(net "M_B_CPU0_SA_CB<1>")
	)
	(segment
		(start 311.881266 -276.612604)
		(end 310.879744 -277.614126)
		(width 0.18288)
		(layer "In2.Cu")
		(net "M_B_CPU0_SA_CB<1>")
	)
	(segment
		(start 297.486324 -277.217124)
		(end 297.486324 -277.495254)
		(width 0.18288)
		(layer "In2.Cu")
		(net "M_B_CPU0_SA_CB<1>")
	)
	(segment
		(start 298.51985 -277.641812)
		(end 298.32808 -277.450042)
		(width 0.18288)
		(layer "In2.Cu")
		(net "M_B_CPU0_SA_CB<1>")
	)
	(segment
		(start 311.881266 -276.241764)
		(end 311.881266 -276.612604)
		(width 0.18288)
		(layer "In2.Cu")
		(net "M_B_CPU0_SA_CB<1>")
	)
	(segment
		(start 296.607738 -278.357076)
		(end 296.447718 -278.517096)
		(width 0.18288)
		(layer "In2.Cu")
		(net "M_B_CPU0_SA_CB<1>")
	)
	(segment
		(start 329.69327 -263.710166)
		(end 329.174856 -263.710166)
		(width 0.088646)
		(layer "In2.Cu")
		(net "M_B_CPU0_SA_CB<1>")
	)
	(segment
		(start 299.31741 -277.641812)
		(end 298.51985 -277.641812)
		(width 0.18288)
		(layer "In2.Cu")
		(net "M_B_CPU0_SA_CB<1>")
	)
	(segment
		(start 302.203358 -277.627334)
		(end 302.07712 -277.753572)
		(width 0.18288)
		(layer "In2.Cu")
		(net "M_B_CPU0_SA_CB<1>")
	)
	(segment
		(start 312.500772 -275.622258)
		(end 311.881266 -276.241764)
		(width 0.18288)
		(layer "In2.Cu")
		(net "M_B_CPU0_SA_CB<1>")
	)
	(segment
		(start 333.188564 -261.734554)
		(end 333.188564 -261.7343)
		(width 0.088646)
		(layer "In2.Cu")
		(net "M_B_CPU0_SA_CB<1>")
	)
	(segment
		(start 304.406046 -277.638002)
		(end 304.107088 -277.93696)
		(width 0.18288)
		(layer "In2.Cu")
		(net "M_B_CPU0_SA_CB<1>")
	)
	(segment
		(start 326.227186 -265.251946)
		(end 323.986144 -266.180316)
		(width 0.18288)
		(layer "In2.Cu")
		(net "M_B_CPU0_SA_CB<1>")
	)
	(segment
		(start 298.32808 -277.18766)
		(end 298.16806 -277.02764)
		(width 0.18288)
		(layer "In2.Cu")
		(net "M_B_CPU0_SA_CB<1>")
	)
	(segment
		(start 302.9585 -277.627334)
		(end 302.203358 -277.627334)
		(width 0.18288)
		(layer "In2.Cu")
		(net "M_B_CPU0_SA_CB<1>")
	)
	(segment
		(start 298.32808 -277.450042)
		(end 298.32808 -277.18766)
		(width 0.18288)
		(layer "In2.Cu")
		(net "M_B_CPU0_SA_CB<1>")
	)
	(segment
		(start 306.318666 -277.638002)
		(end 304.406046 -277.638002)
		(width 0.18288)
		(layer "In2.Cu")
		(net "M_B_CPU0_SA_CB<1>")
	)
	(segment
		(start 297.486324 -277.495254)
		(end 297.310302 -277.671276)
		(width 0.18288)
		(layer "In2.Cu")
		(net "M_B_CPU0_SA_CB<1>")
	)
	(segment
		(start 313.271662 -275.622258)
		(end 312.500772 -275.622258)
		(width 0.18288)
		(layer "In2.Cu")
		(net "M_B_CPU0_SA_CB<1>")
	)
	(segment
		(start 304.107088 -277.93696)
		(end 303.268126 -277.93696)
		(width 0.18288)
		(layer "In2.Cu")
		(net "M_B_CPU0_SA_CB<1>")
	)
	(segment
		(start 302.07712 -277.753572)
		(end 300.64075 -277.753572)
		(width 0.18288)
		(layer "In2.Cu")
		(net "M_B_CPU0_SA_CB<1>")
	)
	(segment
		(start 306.639976 -277.959312)
		(end 306.318666 -277.638002)
		(width 0.18288)
		(layer "In2.Cu")
		(net "M_B_CPU0_SA_CB<1>")
	)
	(segment
		(start 298.16806 -277.02764)
		(end 297.675808 -277.02764)
		(width 0.18288)
		(layer "In2.Cu")
		(net "M_B_CPU0_SA_CB<1>")
	)
	(segment
		(start 307.410612 -277.614126)
		(end 307.065426 -277.959312)
		(width 0.18288)
		(layer "In2.Cu")
		(net "M_B_CPU0_SA_CB<1>")
	)
	(segment
		(start 299.445426 -277.513796)
		(end 299.31741 -277.641812)
		(width 0.18288)
		(layer "In2.Cu")
		(net "M_B_CPU0_SA_CB<1>")
	)
	(segment
		(start 295.946068 -278.517096)
		(end 295.775888 -278.346916)
		(width 0.18288)
		(layer "In2.Cu")
		(net "M_B_CPU0_SA_CB<1>")
	)
	(segment
		(start 296.447718 -278.517096)
		(end 295.946068 -278.517096)
		(width 0.18288)
		(layer "In2.Cu")
		(net "M_B_CPU0_SA_CB<1>")
	)
	(segment
		(start 331.966062 -261.809992)
		(end 331.667866 -261.809992)
		(width 0.088646)
		(layer "In2.Cu")
		(net "M_B_CPU0_SA_CB<1>")
	)
	(segment
		(start 303.268126 -277.93696)
		(end 302.9585 -277.627334)
		(width 0.18288)
		(layer "In2.Cu")
		(net "M_B_CPU0_SA_CB<1>")
	)
	(segment
		(start 300.400974 -277.513796)
		(end 299.445426 -277.513796)
		(width 0.18288)
		(layer "In2.Cu")
		(net "M_B_CPU0_SA_CB<1>")
	)
	(segment
		(start 296.866056 -277.671276)
		(end 296.607738 -277.929594)
		(width 0.18288)
		(layer "In2.Cu")
		(net "M_B_CPU0_SA_CB<1>")
	)
	(segment
		(start 295.775888 -277.409656)
		(end 295.582848 -277.216616)
		(width 0.18288)
		(layer "In2.Cu")
		(net "M_B_CPU0_SA_CB<1>")
	)
	(segment
		(start 307.065426 -277.959312)
		(end 306.639976 -277.959312)
		(width 0.18288)
		(layer "In2.Cu")
		(net "M_B_CPU0_SA_CB<1>")
	)
	(segment
		(start 295.775888 -278.346916)
		(end 295.775888 -277.409656)
		(width 0.18288)
		(layer "In2.Cu")
		(net "M_B_CPU0_SA_CB<1>")
	)
	(arc
		(start 334.50276 -261.734554)
		(mid 334.315562 -261.684377)
		(end 334.128364 -261.734554)
		(width 0.088646)
		(layer "In2.Cu")
		(net "M_B_CPU0_SA_CB<1>")
	)
	(arc
		(start 333.188564 -261.7343)
		(mid 332.905862 -261.810076)
		(end 332.62316 -261.7343)
		(width 0.088646)
		(layer "In2.Cu")
		(net "M_B_CPU0_SA_CB<1>")
	)
	(arc
		(start 334.128364 -261.734554)
		(mid 333.845662 -261.81033)
		(end 333.56296 -261.734554)
		(width 0.088646)
		(layer "In2.Cu")
		(net "M_B_CPU0_SA_CB<1>")
	)
	(arc
		(start 335.068164 -261.734554)
		(mid 334.785462 -261.81033)
		(end 334.50276 -261.734554)
		(width 0.088646)
		(layer "In2.Cu")
		(net "M_B_CPU0_SA_CB<1>")
	)
	(arc
		(start 335.44256 -261.734554)
		(mid 335.255362 -261.684377)
		(end 335.068164 -261.734554)
		(width 0.088646)
		(layer "In2.Cu")
		(net "M_B_CPU0_SA_CB<1>")
	)
	(arc
		(start 332.62316 -261.7343)
		(mid 332.435962 -261.684157)
		(end 332.248764 -261.7343)
		(width 0.088646)
		(layer "In2.Cu")
		(net "M_B_CPU0_SA_CB<1>")
	)
	(arc
		(start 336.169762 -261.594092)
		(mid 335.832384 -261.799986)
		(end 335.44256 -261.734554)
		(width 0.088646)
		(layer "In2.Cu")
		(net "M_B_CPU0_SA_CB<1>")
	)
	(arc
		(start 333.56296 -261.734554)
		(mid 333.375762 -261.684377)
		(end 333.188564 -261.734554)
		(width 0.088646)
		(layer "In2.Cu")
		(net "M_B_CPU0_SA_CB<1>")
	)
	(arc
		(start 332.248764 -261.7343)
		(mid 332.112398 -261.790778)
		(end 331.966062 -261.809992)
		(width 0.088646)
		(layer "In2.Cu")
		(net "M_B_CPU0_SA_CB<1>")
	)
	(segment
		(start 288.46018 -278.982678)
		(end 288.28746 -279.155398)
		(width 0.20066)
		(layer "F.Cu")
		(net "M_B_CPU0_SA_CB<0>")
	)
	(segment
		(start 292.430454 -278.916638)
		(end 292.005512 -278.491696)
		(width 0.20066)
		(layer "F.Cu")
		(net "M_B_CPU0_SA_CB<0>")
	)
	(segment
		(start 289.231578 -278.483568)
		(end 288.66973 -278.483568)
		(width 0.20066)
		(layer "F.Cu")
		(net "M_B_CPU0_SA_CB<0>")
	)
	(segment
		(start 287.828736 -279.155398)
		(end 287.589976 -278.916638)
		(width 0.20066)
		(layer "F.Cu")
		(net "M_B_CPU0_SA_CB<0>")
	)
	(segment
		(start 288.66973 -278.483568)
		(end 288.46018 -278.693118)
		(width 0.20066)
		(layer "F.Cu")
		(net "M_B_CPU0_SA_CB<0>")
	)
	(segment
		(start 291.556694 -278.491696)
		(end 289.48761 -278.491696)
		(width 0.1016)
		(layer "F.Cu")
		(net "M_B_CPU0_SA_CB<0>")
	)
	(segment
		(start 288.46018 -278.693118)
		(end 288.46018 -278.982678)
		(width 0.20066)
		(layer "F.Cu")
		(net "M_B_CPU0_SA_CB<0>")
	)
	(segment
		(start 337.134962 -261.522718)
		(end 337.135216 -261.522972)
		(width 0.20066)
		(layer "F.Cu")
		(net "M_B_CPU0_SA_CB<0>")
	)
	(segment
		(start 289.48761 -278.491696)
		(end 289.239706 -278.491696)
		(width 0.101854)
		(layer "F.Cu")
		(net "M_B_CPU0_SA_CB<0>")
	)
	(segment
		(start 294.904414 -278.916638)
		(end 293.799514 -278.916638)
		(width 0.20066)
		(layer "F.Cu")
		(net "M_B_CPU0_SA_CB<0>")
	)
	(segment
		(start 293.799514 -278.916638)
		(end 292.430454 -278.916638)
		(width 0.20066)
		(layer "F.Cu")
		(net "M_B_CPU0_SA_CB<0>")
	)
	(segment
		(start 337.135216 -261.522972)
		(end 337.135216 -262.058658)
		(width 0.20066)
		(layer "F.Cu")
		(net "M_B_CPU0_SA_CB<0>")
	)
	(segment
		(start 287.589976 -278.916638)
		(end 286.255714 -278.916638)
		(width 0.20066)
		(layer "F.Cu")
		(net "M_B_CPU0_SA_CB<0>")
	)
	(segment
		(start 288.28746 -279.155398)
		(end 287.828736 -279.155398)
		(width 0.20066)
		(layer "F.Cu")
		(net "M_B_CPU0_SA_CB<0>")
	)
	(segment
		(start 292.005512 -278.491696)
		(end 291.556694 -278.491696)
		(width 0.20066)
		(layer "F.Cu")
		(net "M_B_CPU0_SA_CB<0>")
	)
	(segment
		(start 289.239706 -278.491696)
		(end 289.231578 -278.483568)
		(width 0.101854)
		(layer "F.Cu")
		(net "M_B_CPU0_SA_CB<0>")
	)
	(segment
		(start 304.502566 -279.36317)
		(end 303.660556 -280.20518)
		(width 0.18288)
		(layer "In2.Cu")
		(net "M_B_CPU0_SA_CB<0>")
	)
	(segment
		(start 298.07789 -279.341834)
		(end 298.033694 -279.38603)
		(width 0.18288)
		(layer "In2.Cu")
		(net "M_B_CPU0_SA_CB<0>")
	)
	(segment
		(start 314.55106 -277.052786)
		(end 314.55106 -277.740364)
		(width 0.18288)
		(layer "In2.Cu")
		(net "M_B_CPU0_SA_CB<0>")
	)
	(segment
		(start 311.563766 -278.510492)
		(end 309.584852 -279.33015)
		(width 0.18288)
		(layer "In2.Cu")
		(net "M_B_CPU0_SA_CB<0>")
	)
	(segment
		(start 311.743598 -278.482552)
		(end 311.563766 -278.510492)
		(width 0.18288)
		(layer "In2.Cu")
		(net "M_B_CPU0_SA_CB<0>")
	)
	(segment
		(start 295.373806 -279.38603)
		(end 294.904414 -278.916638)
		(width 0.18288)
		(layer "In2.Cu")
		(net "M_B_CPU0_SA_CB<0>")
	)
	(segment
		(start 331.966062 -262.49757)
		(end 331.70622 -262.49757)
		(width 0.088646)
		(layer "In2.Cu")
		(net "M_B_CPU0_SA_CB<0>")
	)
	(segment
		(start 314.55106 -277.740364)
		(end 313.808872 -278.482552)
		(width 0.18288)
		(layer "In2.Cu")
		(net "M_B_CPU0_SA_CB<0>")
	)
	(segment
		(start 326.832976 -266.101068)
		(end 324.561962 -267.041884)
		(width 0.18288)
		(layer "In2.Cu")
		(net "M_B_CPU0_SA_CB<0>")
	)
	(segment
		(start 309.584852 -279.33015)
		(end 307.320188 -279.33015)
		(width 0.18288)
		(layer "In2.Cu")
		(net "M_B_CPU0_SA_CB<0>")
	)
	(segment
		(start 303.660556 -280.20518)
		(end 299.912278 -280.20518)
		(width 0.18288)
		(layer "In2.Cu")
		(net "M_B_CPU0_SA_CB<0>")
	)
	(segment
		(start 324.561962 -267.041884)
		(end 314.55106 -277.052786)
		(width 0.18288)
		(layer "In2.Cu")
		(net "M_B_CPU0_SA_CB<0>")
	)
	(segment
		(start 336.490056 -262.541004)
		(end 336.477864 -262.548116)
		(width 0.088646)
		(layer "In2.Cu")
		(net "M_B_CPU0_SA_CB<0>")
	)
	(segment
		(start 337.44789 -262.058658)
		(end 337.50504 -262.001508)
		(width 0.088646)
		(layer "In2.Cu")
		(net "M_B_CPU0_SA_CB<0>")
	)
	(segment
		(start 299.496226 -279.534874)
		(end 299.303186 -279.341834)
		(width 0.18288)
		(layer "In2.Cu")
		(net "M_B_CPU0_SA_CB<0>")
	)
	(segment
		(start 331.70622 -262.49757)
		(end 329.802744 -264.401046)
		(width 0.088646)
		(layer "In2.Cu")
		(net "M_B_CPU0_SA_CB<0>")
	)
	(segment
		(start 313.808872 -278.482552)
		(end 311.743598 -278.482552)
		(width 0.18288)
		(layer "In2.Cu")
		(net "M_B_CPU0_SA_CB<0>")
	)
	(segment
		(start 299.303186 -279.341834)
		(end 298.07789 -279.341834)
		(width 0.18288)
		(layer "In2.Cu")
		(net "M_B_CPU0_SA_CB<0>")
	)
	(segment
		(start 306.468018 -279.532588)
		(end 306.2986 -279.36317)
		(width 0.18288)
		(layer "In2.Cu")
		(net "M_B_CPU0_SA_CB<0>")
	)
	(segment
		(start 307.320188 -279.33015)
		(end 307.11775 -279.532588)
		(width 0.18288)
		(layer "In2.Cu")
		(net "M_B_CPU0_SA_CB<0>")
	)
	(segment
		(start 337.135216 -262.058658)
		(end 337.44789 -262.058658)
		(width 0.088646)
		(layer "In2.Cu")
		(net "M_B_CPU0_SA_CB<0>")
	)
	(segment
		(start 329.802744 -264.401046)
		(end 329.174856 -264.401046)
		(width 0.088646)
		(layer "In2.Cu")
		(net "M_B_CPU0_SA_CB<0>")
	)
	(segment
		(start 329.174856 -264.401046)
		(end 328.532998 -264.401046)
		(width 0.18288)
		(layer "In2.Cu")
		(net "M_B_CPU0_SA_CB<0>")
	)
	(segment
		(start 307.11775 -279.532588)
		(end 306.468018 -279.532588)
		(width 0.18288)
		(layer "In2.Cu")
		(net "M_B_CPU0_SA_CB<0>")
	)
	(segment
		(start 336.948018 -261.7343)
		(end 336.939128 -261.73938)
		(width 0.088646)
		(layer "In2.Cu")
		(net "M_B_CPU0_SA_CB<0>")
	)
	(segment
		(start 306.2986 -279.36317)
		(end 304.502566 -279.36317)
		(width 0.18288)
		(layer "In2.Cu")
		(net "M_B_CPU0_SA_CB<0>")
	)
	(segment
		(start 328.532998 -264.401046)
		(end 326.832976 -266.101068)
		(width 0.18288)
		(layer "In2.Cu")
		(net "M_B_CPU0_SA_CB<0>")
	)
	(segment
		(start 299.496226 -279.789128)
		(end 299.496226 -279.534874)
		(width 0.18288)
		(layer "In2.Cu")
		(net "M_B_CPU0_SA_CB<0>")
	)
	(segment
		(start 299.912278 -280.20518)
		(end 299.496226 -279.789128)
		(width 0.18288)
		(layer "In2.Cu")
		(net "M_B_CPU0_SA_CB<0>")
	)
	(segment
		(start 298.033694 -279.38603)
		(end 295.373806 -279.38603)
		(width 0.18288)
		(layer "In2.Cu")
		(net "M_B_CPU0_SA_CB<0>")
	)
	(arc
		(start 333.658464 -262.548116)
		(mid 333.375762 -262.623892)
		(end 333.09306 -262.548116)
		(width 0.088646)
		(layer "In2.Cu")
		(net "M_B_CPU0_SA_CB<0>")
	)
	(arc
		(start 334.598264 -262.548116)
		(mid 334.315562 -262.623892)
		(end 334.03286 -262.548116)
		(width 0.088646)
		(layer "In2.Cu")
		(net "M_B_CPU0_SA_CB<0>")
	)
	(arc
		(start 334.03286 -262.548116)
		(mid 333.845662 -262.497973)
		(end 333.658464 -262.548116)
		(width 0.088646)
		(layer "In2.Cu")
		(net "M_B_CPU0_SA_CB<0>")
	)
	(arc
		(start 336.477864 -262.548116)
		(mid 336.195162 -262.623892)
		(end 335.91246 -262.548116)
		(width 0.088646)
		(layer "In2.Cu")
		(net "M_B_CPU0_SA_CB<0>")
	)
	(arc
		(start 333.09306 -262.548116)
		(mid 332.905862 -262.497973)
		(end 332.718664 -262.548116)
		(width 0.088646)
		(layer "In2.Cu")
		(net "M_B_CPU0_SA_CB<0>")
	)
	(arc
		(start 332.718664 -262.548116)
		(mid 332.435962 -262.623892)
		(end 332.15326 -262.548116)
		(width 0.088646)
		(layer "In2.Cu")
		(net "M_B_CPU0_SA_CB<0>")
	)
	(arc
		(start 332.15326 -262.548116)
		(mid 332.062984 -262.510542)
		(end 331.966062 -262.49757)
		(width 0.088646)
		(layer "In2.Cu")
		(net "M_B_CPU0_SA_CB<0>")
	)
	(arc
		(start 337.50504 -262.001508)
		(mid 337.444097 -261.847145)
		(end 337.322414 -261.7343)
		(width 0.088646)
		(layer "In2.Cu")
		(net "M_B_CPU0_SA_CB<0>")
	)
	(arc
		(start 334.97266 -262.548116)
		(mid 334.785462 -262.497973)
		(end 334.598264 -262.548116)
		(width 0.088646)
		(layer "In2.Cu")
		(net "M_B_CPU0_SA_CB<0>")
	)
	(arc
		(start 335.538064 -262.548116)
		(mid 335.255362 -262.623892)
		(end 334.97266 -262.548116)
		(width 0.088646)
		(layer "In2.Cu")
		(net "M_B_CPU0_SA_CB<0>")
	)
	(arc
		(start 336.760566 -262.058658)
		(mid 336.688331 -262.335182)
		(end 336.490056 -262.541004)
		(width 0.088646)
		(layer "In2.Cu")
		(net "M_B_CPU0_SA_CB<0>")
	)
	(arc
		(start 337.322414 -261.7343)
		(mid 337.135216 -261.684157)
		(end 336.948018 -261.7343)
		(width 0.088646)
		(layer "In2.Cu")
		(net "M_B_CPU0_SA_CB<0>")
	)
	(arc
		(start 335.91246 -262.548116)
		(mid 335.725262 -262.497973)
		(end 335.538064 -262.548116)
		(width 0.088646)
		(layer "In2.Cu")
		(net "M_B_CPU0_SA_CB<0>")
	)
	(arc
		(start 336.939128 -261.73938)
		(mid 336.808214 -261.87574)
		(end 336.760566 -262.058658)
		(width 0.088646)
		(layer "In2.Cu")
		(net "M_B_CPU0_SA_CB<0>")
	)
	(segment
		(start 289.231578 -260.632956)
		(end 288.62274 -260.632956)
		(width 0.20066)
		(layer "F.Cu")
		(net "M_B_CPU0_SA_CA<6>")
	)
	(segment
		(start 293.799514 -261.066788)
		(end 292.160198 -261.066788)
		(width 0.20066)
		(layer "F.Cu")
		(net "M_B_CPU0_SA_CA<6>")
	)
	(segment
		(start 292.160198 -261.066788)
		(end 291.735256 -260.641846)
		(width 0.20066)
		(layer "F.Cu")
		(net "M_B_CPU0_SA_CA<6>")
	)
	(segment
		(start 294.904414 -261.066788)
		(end 293.799514 -261.066788)
		(width 0.20066)
		(layer "F.Cu")
		(net "M_B_CPU0_SA_CA<6>")
	)
	(segment
		(start 287.801304 -261.278116)
		(end 287.589976 -261.066788)
		(width 0.20066)
		(layer "F.Cu")
		(net "M_B_CPU0_SA_CA<6>")
	)
	(segment
		(start 287.589976 -261.066788)
		(end 286.255714 -261.066788)
		(width 0.20066)
		(layer "F.Cu")
		(net "M_B_CPU0_SA_CA<6>")
	)
	(segment
		(start 291.556694 -260.641846)
		(end 291.225986 -260.641846)
		(width 0.101854)
		(layer "F.Cu")
		(net "M_B_CPU0_SA_CA<6>")
	)
	(segment
		(start 288.62274 -260.632956)
		(end 288.46018 -260.795516)
		(width 0.20066)
		(layer "F.Cu")
		(net "M_B_CPU0_SA_CA<6>")
	)
	(segment
		(start 291.225986 -260.641846)
		(end 289.240468 -260.641846)
		(width 0.1016)
		(layer "F.Cu")
		(net "M_B_CPU0_SA_CA<6>")
	)
	(segment
		(start 341.724234 -249.341894)
		(end 341.724234 -248.806208)
		(width 0.20066)
		(layer "F.Cu")
		(net "M_B_CPU0_SA_CA<6>")
	)
	(segment
		(start 288.46018 -261.123684)
		(end 288.305748 -261.278116)
		(width 0.20066)
		(layer "F.Cu")
		(net "M_B_CPU0_SA_CA<6>")
	)
	(segment
		(start 289.240468 -260.641846)
		(end 289.231578 -260.632956)
		(width 0.1016)
		(layer "F.Cu")
		(net "M_B_CPU0_SA_CA<6>")
	)
	(segment
		(start 341.72398 -249.342148)
		(end 341.724234 -249.341894)
		(width 0.20066)
		(layer "F.Cu")
		(net "M_B_CPU0_SA_CA<6>")
	)
	(segment
		(start 288.46018 -260.795516)
		(end 288.46018 -261.123684)
		(width 0.20066)
		(layer "F.Cu")
		(net "M_B_CPU0_SA_CA<6>")
	)
	(segment
		(start 291.735256 -260.641846)
		(end 291.556694 -260.641846)
		(width 0.20066)
		(layer "F.Cu")
		(net "M_B_CPU0_SA_CA<6>")
	)
	(segment
		(start 288.305748 -261.278116)
		(end 287.801304 -261.278116)
		(width 0.20066)
		(layer "F.Cu")
		(net "M_B_CPU0_SA_CA<6>")
	)
	(segment
		(start 297.017948 -261.49173)
		(end 296.876724 -261.632954)
		(width 0.18288)
		(layer "In2.Cu")
		(net "M_B_CPU0_SA_CA<6>")
	)
	(segment
		(start 299.455332 -261.221982)
		(end 299.185584 -261.49173)
		(width 0.18288)
		(layer "In2.Cu")
		(net "M_B_CPU0_SA_CA<6>")
	)
	(segment
		(start 299.185584 -261.49173)
		(end 297.017948 -261.49173)
		(width 0.18288)
		(layer "In2.Cu")
		(net "M_B_CPU0_SA_CA<6>")
	)
	(segment
		(start 303.65192 -258.957572)
		(end 303.27346 -259.06095)
		(width 0.18288)
		(layer "In2.Cu")
		(net "M_B_CPU0_SA_CA<6>")
	)
	(segment
		(start 320.267584 -255.897126)
		(end 319.80759 -256.087626)
		(width 0.18288)
		(layer "In2.Cu")
		(net "M_B_CPU0_SA_CA<6>")
	)
	(segment
		(start 318.925956 -256.452624)
		(end 313.361578 -257.559302)
		(width 0.18288)
		(layer "In2.Cu")
		(net "M_B_CPU0_SA_CA<6>")
	)
	(segment
		(start 330.849732 -252.628908)
		(end 327.581514 -255.897126)
		(width 0.18288)
		(layer "In2.Cu")
		(net "M_B_CPU0_SA_CA<6>")
	)
	(segment
		(start 307.571902 -257.559302)
		(end 306.198016 -257.784854)
		(width 0.18288)
		(layer "In2.Cu")
		(net "M_B_CPU0_SA_CA<6>")
	)
	(segment
		(start 300.536356 -260.676898)
		(end 300.370494 -260.84276)
		(width 0.18288)
		(layer "In2.Cu")
		(net "M_B_CPU0_SA_CA<6>")
	)
	(segment
		(start 342.94699 -250.114562)
		(end 342.94699 -250.877832)
		(width 0.18288)
		(layer "In2.Cu")
		(net "M_B_CPU0_SA_CA<6>")
	)
	(segment
		(start 342.75903 -249.797062)
		(end 342.94699 -249.985022)
		(width 0.088646)
		(layer "In2.Cu")
		(net "M_B_CPU0_SA_CA<6>")
	)
	(segment
		(start 327.581514 -255.897126)
		(end 320.267584 -255.897126)
		(width 0.18288)
		(layer "In2.Cu")
		(net "M_B_CPU0_SA_CA<6>")
	)
	(segment
		(start 304.490628 -258.957572)
		(end 303.65192 -258.957572)
		(width 0.18288)
		(layer "In2.Cu")
		(net "M_B_CPU0_SA_CA<6>")
	)
	(segment
		(start 342.11006 -251.714762)
		(end 339.9028 -252.628908)
		(width 0.18288)
		(layer "In2.Cu")
		(net "M_B_CPU0_SA_CA<6>")
	)
	(segment
		(start 342.94699 -250.877832)
		(end 342.11006 -251.714762)
		(width 0.18288)
		(layer "In2.Cu")
		(net "M_B_CPU0_SA_CA<6>")
	)
	(segment
		(start 304.631344 -258.901946)
		(end 304.490628 -258.957572)
		(width 0.18288)
		(layer "In2.Cu")
		(net "M_B_CPU0_SA_CA<6>")
	)
	(segment
		(start 342.94699 -249.985022)
		(end 342.94699 -250.114562)
		(width 0.088646)
		(layer "In2.Cu")
		(net "M_B_CPU0_SA_CA<6>")
	)
	(segment
		(start 306.198016 -257.784854)
		(end 304.631344 -258.901946)
		(width 0.18288)
		(layer "In2.Cu")
		(net "M_B_CPU0_SA_CA<6>")
	)
	(segment
		(start 319.80759 -256.087626)
		(end 318.925956 -256.452624)
		(width 0.18288)
		(layer "In2.Cu")
		(net "M_B_CPU0_SA_CA<6>")
	)
	(segment
		(start 339.9028 -252.628908)
		(end 330.849732 -252.628908)
		(width 0.18288)
		(layer "In2.Cu")
		(net "M_B_CPU0_SA_CA<6>")
	)
	(segment
		(start 303.27346 -259.06095)
		(end 300.536356 -260.676898)
		(width 0.18288)
		(layer "In2.Cu")
		(net "M_B_CPU0_SA_CA<6>")
	)
	(segment
		(start 342.448642 -249.11431)
		(end 342.476582 -249.130566)
		(width 0.088646)
		(layer "In2.Cu")
		(net "M_B_CPU0_SA_CA<6>")
	)
	(segment
		(start 300.370494 -260.84276)
		(end 299.455332 -261.221982)
		(width 0.18288)
		(layer "In2.Cu")
		(net "M_B_CPU0_SA_CA<6>")
	)
	(segment
		(start 296.271696 -261.632954)
		(end 294.904414 -261.066788)
		(width 0.18288)
		(layer "In2.Cu")
		(net "M_B_CPU0_SA_CA<6>")
	)
	(segment
		(start 313.361578 -257.559302)
		(end 307.571902 -257.559302)
		(width 0.18288)
		(layer "In2.Cu")
		(net "M_B_CPU0_SA_CA<6>")
	)
	(segment
		(start 342.75903 -249.61977)
		(end 342.75903 -249.797062)
		(width 0.088646)
		(layer "In2.Cu")
		(net "M_B_CPU0_SA_CA<6>")
	)
	(segment
		(start 341.724234 -248.806208)
		(end 342.448642 -249.11431)
		(width 0.088646)
		(layer "In2.Cu")
		(net "M_B_CPU0_SA_CA<6>")
	)
	(segment
		(start 296.876724 -261.632954)
		(end 296.271696 -261.632954)
		(width 0.18288)
		(layer "In2.Cu")
		(net "M_B_CPU0_SA_CA<6>")
	)
	(arc
		(start 342.476582 -249.130566)
		(mid 342.683342 -249.337329)
		(end 342.75903 -249.61977)
		(width 0.088646)
		(layer "In2.Cu")
		(net "M_B_CPU0_SA_CA<6>")
	)
	(segment
		(start 338.074762 -253.383796)
		(end 338.074762 -253.919736)
		(width 0.20066)
		(layer "F.Cu")
		(net "M_B_CPU0_SA_CA<5>")
	)
	(segment
		(start 292.67531 -262.355838)
		(end 292.321488 -262.355838)
		(width 0.20066)
		(layer "F.Cu")
		(net "M_B_CPU0_SA_CA<5>")
	)
	(segment
		(start 295.693846 -262.040878)
		(end 295.693846 -262.192516)
		(width 0.20066)
		(layer "F.Cu")
		(net "M_B_CPU0_SA_CA<5>")
	)
	(segment
		(start 297.08348 -261.916672)
		(end 296.875962 -262.12419)
		(width 0.20066)
		(layer "F.Cu")
		(net "M_B_CPU0_SA_CA<5>")
	)
	(segment
		(start 295.82237 -261.912354)
		(end 295.693846 -262.040878)
		(width 0.20066)
		(layer "F.Cu")
		(net "M_B_CPU0_SA_CA<5>")
	)
	(segment
		(start 292.689534 -262.341614)
		(end 292.67531 -262.355838)
		(width 0.101854)
		(layer "F.Cu")
		(net "M_B_CPU0_SA_CA<5>")
	)
	(segment
		(start 296.42943 -262.12419)
		(end 296.217594 -261.912354)
		(width 0.20066)
		(layer "F.Cu")
		(net "M_B_CPU0_SA_CA<5>")
	)
	(segment
		(start 292.178994 -262.213344)
		(end 292.178994 -262.042656)
		(width 0.20066)
		(layer "F.Cu")
		(net "M_B_CPU0_SA_CA<5>")
	)
	(segment
		(start 299.029882 -261.916672)
		(end 297.899582 -261.916672)
		(width 0.20066)
		(layer "F.Cu")
		(net "M_B_CPU0_SA_CA<5>")
	)
	(segment
		(start 295.693846 -262.192516)
		(end 295.544748 -262.341614)
		(width 0.20066)
		(layer "F.Cu")
		(net "M_B_CPU0_SA_CA<5>")
	)
	(segment
		(start 292.178994 -262.042656)
		(end 292.05301 -261.916672)
		(width 0.20066)
		(layer "F.Cu")
		(net "M_B_CPU0_SA_CA<5>")
	)
	(segment
		(start 296.875962 -262.12419)
		(end 296.42943 -262.12419)
		(width 0.20066)
		(layer "F.Cu")
		(net "M_B_CPU0_SA_CA<5>")
	)
	(segment
		(start 292.321488 -262.355838)
		(end 292.178994 -262.213344)
		(width 0.20066)
		(layer "F.Cu")
		(net "M_B_CPU0_SA_CA<5>")
	)
	(segment
		(start 296.217594 -261.912354)
		(end 295.82237 -261.912354)
		(width 0.20066)
		(layer "F.Cu")
		(net "M_B_CPU0_SA_CA<5>")
	)
	(segment
		(start 297.899582 -261.916672)
		(end 297.08348 -261.916672)
		(width 0.20066)
		(layer "F.Cu")
		(net "M_B_CPU0_SA_CA<5>")
	)
	(segment
		(start 295.000426 -262.341614)
		(end 292.927532 -262.341614)
		(width 0.1016)
		(layer "F.Cu")
		(net "M_B_CPU0_SA_CA<5>")
	)
	(segment
		(start 295.544748 -262.341614)
		(end 295.000426 -262.341614)
		(width 0.20066)
		(layer "F.Cu")
		(net "M_B_CPU0_SA_CA<5>")
	)
	(segment
		(start 292.05301 -261.916672)
		(end 290.355782 -261.916672)
		(width 0.20066)
		(layer "F.Cu")
		(net "M_B_CPU0_SA_CA<5>")
	)
	(segment
		(start 292.927532 -262.341614)
		(end 292.689534 -262.341614)
		(width 0.101854)
		(layer "F.Cu")
		(net "M_B_CPU0_SA_CA<5>")
	)
	(segment
		(start 311.3532 -258.235196)
		(end 311.3532 -258.56184)
		(width 0.18288)
		(layer "In2.Cu")
		(net "M_B_CPU0_SA_CA<5>")
	)
	(segment
		(start 312.36539 -258.075176)
		(end 311.51322 -258.075176)
		(width 0.18288)
		(layer "In2.Cu")
		(net "M_B_CPU0_SA_CA<5>")
	)
	(segment
		(start 303.035716 -260.375146)
		(end 302.73244 -260.678422)
		(width 0.18288)
		(layer "In2.Cu")
		(net "M_B_CPU0_SA_CA<5>")
	)
	(segment
		(start 338.074762 -253.919736)
		(end 337.35137 -253.612396)
		(width 0.088646)
		(layer "In2.Cu")
		(net "M_B_CPU0_SA_CA<5>")
	)
	(segment
		(start 299.627036 -261.916418)
		(end 299.030136 -261.916418)
		(width 0.18288)
		(layer "In2.Cu")
		(net "M_B_CPU0_SA_CA<5>")
	)
	(segment
		(start 337.32216 -253.595378)
		(end 337.321906 -253.595378)
		(width 0.088646)
		(layer "In2.Cu")
		(net "M_B_CPU0_SA_CA<5>")
	)
	(segment
		(start 320.198242 -256.478278)
		(end 318.95542 -256.992882)
		(width 0.18288)
		(layer "In2.Cu")
		(net "M_B_CPU0_SA_CA<5>")
	)
	(segment
		(start 303.035716 -259.981954)
		(end 303.035716 -260.375146)
		(width 0.18288)
		(layer "In2.Cu")
		(net "M_B_CPU0_SA_CA<5>")
	)
	(segment
		(start 299.030136 -261.916418)
		(end 299.029882 -261.916672)
		(width 0.18288)
		(layer "In2.Cu")
		(net "M_B_CPU0_SA_CA<5>")
	)
	(segment
		(start 310.413908 -258.068572)
		(end 309.716424 -258.068572)
		(width 0.18288)
		(layer "In2.Cu")
		(net "M_B_CPU0_SA_CA<5>")
	)
	(segment
		(start 306.707286 -258.982972)
		(end 306.53355 -259.156708)
		(width 0.18288)
		(layer "In2.Cu")
		(net "M_B_CPU0_SA_CA<5>")
	)
	(segment
		(start 335.457292 -253.604014)
		(end 335.44256 -253.595378)
		(width 0.088646)
		(layer "In2.Cu")
		(net "M_B_CPU0_SA_CA<5>")
	)
	(segment
		(start 314.81395 -258.30784)
		(end 314.757562 -258.02463)
		(width 0.18288)
		(layer "In2.Cu")
		(net "M_B_CPU0_SA_CA<5>")
	)
	(segment
		(start 302.27905 -260.760972)
		(end 302.27905 -261.332472)
		(width 0.18288)
		(layer "In2.Cu")
		(net "M_B_CPU0_SA_CA<5>")
	)
	(segment
		(start 331.816202 -253.505462)
		(end 330.461874 -253.505462)
		(width 0.18288)
		(layer "In2.Cu")
		(net "M_B_CPU0_SA_CA<5>")
	)
	(segment
		(start 309.396384 -258.982972)
		(end 308.600602 -258.982972)
		(width 0.18288)
		(layer "In2.Cu")
		(net "M_B_CPU0_SA_CA<5>")
	)
	(segment
		(start 302.3616 -260.678422)
		(end 302.27905 -260.760972)
		(width 0.18288)
		(layer "In2.Cu")
		(net "M_B_CPU0_SA_CA<5>")
	)
	(segment
		(start 315.504068 -258.170426)
		(end 315.35243 -258.397248)
		(width 0.18288)
		(layer "In2.Cu")
		(net "M_B_CPU0_SA_CA<5>")
	)
	(segment
		(start 310.573928 -258.228592)
		(end 310.413908 -258.068572)
		(width 0.18288)
		(layer "In2.Cu")
		(net "M_B_CPU0_SA_CA<5>")
	)
	(segment
		(start 315.35243 -258.397248)
		(end 315.040772 -258.459478)
		(width 0.18288)
		(layer "In2.Cu")
		(net "M_B_CPU0_SA_CA<5>")
	)
	(segment
		(start 311.3532 -258.56184)
		(end 311.19318 -258.72186)
		(width 0.18288)
		(layer "In2.Cu")
		(net "M_B_CPU0_SA_CA<5>")
	)
	(segment
		(start 299.985684 -261.55777)
		(end 299.627036 -261.916418)
		(width 0.18288)
		(layer "In2.Cu")
		(net "M_B_CPU0_SA_CA<5>")
	)
	(segment
		(start 317.200534 -257.341624)
		(end 316.846458 -257.871214)
		(width 0.18288)
		(layer "In2.Cu")
		(net "M_B_CPU0_SA_CA<5>")
	)
	(segment
		(start 330.461874 -253.505462)
		(end 327.72477 -256.242566)
		(width 0.18288)
		(layer "In2.Cu")
		(net "M_B_CPU0_SA_CA<5>")
	)
	(segment
		(start 315.599572 -257.660394)
		(end 315.44768 -257.887216)
		(width 0.18288)
		(layer "In2.Cu")
		(net "M_B_CPU0_SA_CA<5>")
	)
	(segment
		(start 309.556404 -258.228592)
		(end 309.556404 -258.822952)
		(width 0.18288)
		(layer "In2.Cu")
		(net "M_B_CPU0_SA_CA<5>")
	)
	(segment
		(start 306.53355 -259.156708)
		(end 306.53355 -259.450332)
		(width 0.18288)
		(layer "In2.Cu")
		(net "M_B_CPU0_SA_CA<5>")
	)
	(segment
		(start 337.35137 -253.612396)
		(end 337.32216 -253.595378)
		(width 0.088646)
		(layer "In2.Cu")
		(net "M_B_CPU0_SA_CA<5>")
	)
	(segment
		(start 309.716424 -258.068572)
		(end 309.556404 -258.228592)
		(width 0.18288)
		(layer "In2.Cu")
		(net "M_B_CPU0_SA_CA<5>")
	)
	(segment
		(start 314.530994 -257.872992)
		(end 313.548268 -258.068572)
		(width 0.18288)
		(layer "In2.Cu")
		(net "M_B_CPU0_SA_CA<5>")
	)
	(segment
		(start 334.517492 -253.604014)
		(end 334.50276 -253.595378)
		(width 0.088646)
		(layer "In2.Cu")
		(net "M_B_CPU0_SA_CA<5>")
	)
	(segment
		(start 304.284888 -259.542788)
		(end 303.474882 -259.542788)
		(width 0.18288)
		(layer "In2.Cu")
		(net "M_B_CPU0_SA_CA<5>")
	)
	(segment
		(start 327.72477 -256.242566)
		(end 320.767202 -256.242566)
		(width 0.18288)
		(layer "In2.Cu")
		(net "M_B_CPU0_SA_CA<5>")
	)
	(segment
		(start 320.767202 -256.242566)
		(end 320.198242 -256.478278)
		(width 0.18288)
		(layer "In2.Cu")
		(net "M_B_CPU0_SA_CA<5>")
	)
	(segment
		(start 336.397092 -253.604014)
		(end 336.38236 -253.595378)
		(width 0.088646)
		(layer "In2.Cu")
		(net "M_B_CPU0_SA_CA<5>")
	)
	(segment
		(start 300.64075 -261.548372)
		(end 300.57471 -261.482332)
		(width 0.18288)
		(layer "In2.Cu")
		(net "M_B_CPU0_SA_CA<5>")
	)
	(segment
		(start 333.577692 -253.604014)
		(end 333.56296 -253.595378)
		(width 0.088646)
		(layer "In2.Cu")
		(net "M_B_CPU0_SA_CA<5>")
	)
	(segment
		(start 318.95542 -256.992882)
		(end 317.200534 -257.341624)
		(width 0.18288)
		(layer "In2.Cu")
		(net "M_B_CPU0_SA_CA<5>")
	)
	(segment
		(start 315.91123 -257.598164)
		(end 315.599572 -257.660394)
		(width 0.18288)
		(layer "In2.Cu")
		(net "M_B_CPU0_SA_CA<5>")
	)
	(segment
		(start 315.040772 -258.459478)
		(end 314.81395 -258.30784)
		(width 0.18288)
		(layer "In2.Cu")
		(net "M_B_CPU0_SA_CA<5>")
	)
	(segment
		(start 332.506066 -253.505462)
		(end 331.816202 -253.505462)
		(width 0.088646)
		(layer "In2.Cu")
		(net "M_B_CPU0_SA_CA<5>")
	)
	(segment
		(start 311.51322 -258.075176)
		(end 311.3532 -258.235196)
		(width 0.18288)
		(layer "In2.Cu")
		(net "M_B_CPU0_SA_CA<5>")
	)
	(segment
		(start 316.846458 -257.871214)
		(end 316.439804 -257.951732)
		(width 0.18288)
		(layer "In2.Cu")
		(net "M_B_CPU0_SA_CA<5>")
	)
	(segment
		(start 300.57471 -261.482332)
		(end 300.167548 -261.482332)
		(width 0.18288)
		(layer "In2.Cu")
		(net "M_B_CPU0_SA_CA<5>")
	)
	(segment
		(start 302.06315 -261.548372)
		(end 300.64075 -261.548372)
		(width 0.18288)
		(layer "In2.Cu")
		(net "M_B_CPU0_SA_CA<5>")
	)
	(segment
		(start 308.214522 -258.089908)
		(end 307.503322 -258.089908)
		(width 0.18288)
		(layer "In2.Cu")
		(net "M_B_CPU0_SA_CA<5>")
	)
	(segment
		(start 313.548268 -258.068572)
		(end 313.16803 -258.44881)
		(width 0.18288)
		(layer "In2.Cu")
		(net "M_B_CPU0_SA_CA<5>")
	)
	(segment
		(start 312.739024 -258.44881)
		(end 312.36539 -258.075176)
		(width 0.18288)
		(layer "In2.Cu")
		(net "M_B_CPU0_SA_CA<5>")
	)
	(segment
		(start 313.16803 -258.44881)
		(end 312.739024 -258.44881)
		(width 0.18288)
		(layer "In2.Cu")
		(net "M_B_CPU0_SA_CA<5>")
	)
	(segment
		(start 306.17033 -259.813552)
		(end 304.555652 -259.813552)
		(width 0.18288)
		(layer "In2.Cu")
		(net "M_B_CPU0_SA_CA<5>")
	)
	(segment
		(start 310.573928 -258.552188)
		(end 310.573928 -258.228592)
		(width 0.18288)
		(layer "In2.Cu")
		(net "M_B_CPU0_SA_CA<5>")
	)
	(segment
		(start 309.556404 -258.822952)
		(end 309.396384 -258.982972)
		(width 0.18288)
		(layer "In2.Cu")
		(net "M_B_CPU0_SA_CA<5>")
	)
	(segment
		(start 314.757562 -258.02463)
		(end 314.530994 -257.872992)
		(width 0.18288)
		(layer "In2.Cu")
		(net "M_B_CPU0_SA_CA<5>")
	)
	(segment
		(start 311.19318 -258.72186)
		(end 310.7436 -258.72186)
		(width 0.18288)
		(layer "In2.Cu")
		(net "M_B_CPU0_SA_CA<5>")
	)
	(segment
		(start 316.439804 -257.951732)
		(end 315.91123 -257.598164)
		(width 0.18288)
		(layer "In2.Cu")
		(net "M_B_CPU0_SA_CA<5>")
	)
	(segment
		(start 307.061616 -258.982972)
		(end 306.707286 -258.982972)
		(width 0.18288)
		(layer "In2.Cu")
		(net "M_B_CPU0_SA_CA<5>")
	)
	(segment
		(start 308.433724 -258.30911)
		(end 308.214522 -258.089908)
		(width 0.18288)
		(layer "In2.Cu")
		(net "M_B_CPU0_SA_CA<5>")
	)
	(segment
		(start 308.600602 -258.982972)
		(end 308.433724 -258.816094)
		(width 0.18288)
		(layer "In2.Cu")
		(net "M_B_CPU0_SA_CA<5>")
	)
	(segment
		(start 310.7436 -258.72186)
		(end 310.573928 -258.552188)
		(width 0.18288)
		(layer "In2.Cu")
		(net "M_B_CPU0_SA_CA<5>")
	)
	(segment
		(start 303.474882 -259.542788)
		(end 303.035716 -259.981954)
		(width 0.18288)
		(layer "In2.Cu")
		(net "M_B_CPU0_SA_CA<5>")
	)
	(segment
		(start 307.264562 -258.780026)
		(end 307.061616 -258.982972)
		(width 0.18288)
		(layer "In2.Cu")
		(net "M_B_CPU0_SA_CA<5>")
	)
	(segment
		(start 302.73244 -260.678422)
		(end 302.3616 -260.678422)
		(width 0.18288)
		(layer "In2.Cu")
		(net "M_B_CPU0_SA_CA<5>")
	)
	(segment
		(start 302.27905 -261.332472)
		(end 302.06315 -261.548372)
		(width 0.18288)
		(layer "In2.Cu")
		(net "M_B_CPU0_SA_CA<5>")
	)
	(segment
		(start 304.555652 -259.813552)
		(end 304.284888 -259.542788)
		(width 0.18288)
		(layer "In2.Cu")
		(net "M_B_CPU0_SA_CA<5>")
	)
	(segment
		(start 308.433724 -258.816094)
		(end 308.433724 -258.30911)
		(width 0.18288)
		(layer "In2.Cu")
		(net "M_B_CPU0_SA_CA<5>")
	)
	(segment
		(start 332.623414 -253.595378)
		(end 332.62316 -253.595378)
		(width 0.088646)
		(layer "In2.Cu")
		(net "M_B_CPU0_SA_CA<5>")
	)
	(segment
		(start 315.44768 -257.887216)
		(end 315.504068 -258.170426)
		(width 0.18288)
		(layer "In2.Cu")
		(net "M_B_CPU0_SA_CA<5>")
	)
	(segment
		(start 306.53355 -259.450332)
		(end 306.17033 -259.813552)
		(width 0.18288)
		(layer "In2.Cu")
		(net "M_B_CPU0_SA_CA<5>")
	)
	(segment
		(start 300.167548 -261.482332)
		(end 299.985684 -261.55777)
		(width 0.18288)
		(layer "In2.Cu")
		(net "M_B_CPU0_SA_CA<5>")
	)
	(segment
		(start 307.503322 -258.089908)
		(end 307.264562 -258.328668)
		(width 0.18288)
		(layer "In2.Cu")
		(net "M_B_CPU0_SA_CA<5>")
	)
	(segment
		(start 307.264562 -258.328668)
		(end 307.264562 -258.780026)
		(width 0.18288)
		(layer "In2.Cu")
		(net "M_B_CPU0_SA_CA<5>")
	)
	(arc
		(start 336.007964 -253.595378)
		(mid 335.733765 -253.671213)
		(end 335.457292 -253.604014)
		(width 0.088646)
		(layer "In2.Cu")
		(net "M_B_CPU0_SA_CA<5>")
	)
	(arc
		(start 333.188564 -253.595378)
		(mid 332.906006 -253.671027)
		(end 332.623414 -253.595378)
		(width 0.088646)
		(layer "In2.Cu")
		(net "M_B_CPU0_SA_CA<5>")
	)
	(arc
		(start 334.128364 -253.595378)
		(mid 333.854165 -253.671213)
		(end 333.577692 -253.604014)
		(width 0.088646)
		(layer "In2.Cu")
		(net "M_B_CPU0_SA_CA<5>")
	)
	(arc
		(start 336.947764 -253.595378)
		(mid 336.673565 -253.671213)
		(end 336.397092 -253.604014)
		(width 0.088646)
		(layer "In2.Cu")
		(net "M_B_CPU0_SA_CA<5>")
	)
	(arc
		(start 332.62316 -253.595378)
		(mid 332.561671 -253.554252)
		(end 332.506066 -253.505462)
		(width 0.088646)
		(layer "In2.Cu")
		(net "M_B_CPU0_SA_CA<5>")
	)
	(arc
		(start 333.56296 -253.595378)
		(mid 333.375762 -253.545235)
		(end 333.188564 -253.595378)
		(width 0.088646)
		(layer "In2.Cu")
		(net "M_B_CPU0_SA_CA<5>")
	)
	(arc
		(start 335.068164 -253.595378)
		(mid 334.793965 -253.671213)
		(end 334.517492 -253.604014)
		(width 0.088646)
		(layer "In2.Cu")
		(net "M_B_CPU0_SA_CA<5>")
	)
	(arc
		(start 337.321906 -253.595378)
		(mid 337.134852 -253.545328)
		(end 336.947764 -253.595378)
		(width 0.088646)
		(layer "In2.Cu")
		(net "M_B_CPU0_SA_CA<5>")
	)
	(arc
		(start 334.50276 -253.595378)
		(mid 334.315562 -253.545235)
		(end 334.128364 -253.595378)
		(width 0.088646)
		(layer "In2.Cu")
		(net "M_B_CPU0_SA_CA<5>")
	)
	(arc
		(start 336.38236 -253.595378)
		(mid 336.195162 -253.545235)
		(end 336.007964 -253.595378)
		(width 0.088646)
		(layer "In2.Cu")
		(net "M_B_CPU0_SA_CA<5>")
	)
	(arc
		(start 335.44256 -253.595378)
		(mid 335.255362 -253.545235)
		(end 335.068164 -253.595378)
		(width 0.088646)
		(layer "In2.Cu")
		(net "M_B_CPU0_SA_CA<5>")
	)
	(segment
		(start 337.134962 -253.383796)
		(end 337.134962 -253.919736)
		(width 0.20066)
		(layer "F.Cu")
		(net "M_B_CPU0_SA_CA<4>")
	)
	(segment
		(start 292.160198 -262.76681)
		(end 291.735256 -262.341868)
		(width 0.20066)
		(layer "F.Cu")
		(net "M_B_CPU0_SA_CA<4>")
	)
	(segment
		(start 294.904414 -262.76681)
		(end 293.799514 -262.76681)
		(width 0.20066)
		(layer "F.Cu")
		(net "M_B_CPU0_SA_CA<4>")
	)
	(segment
		(start 291.735256 -262.341868)
		(end 291.556694 -262.341868)
		(width 0.20066)
		(layer "F.Cu")
		(net "M_B_CPU0_SA_CA<4>")
	)
	(segment
		(start 287.801304 -262.978138)
		(end 287.589976 -262.76681)
		(width 0.20066)
		(layer "F.Cu")
		(net "M_B_CPU0_SA_CA<4>")
	)
	(segment
		(start 289.240468 -262.341868)
		(end 289.231578 -262.332978)
		(width 0.1016)
		(layer "F.Cu")
		(net "M_B_CPU0_SA_CA<4>")
	)
	(segment
		(start 288.62274 -262.332978)
		(end 288.46018 -262.495538)
		(width 0.20066)
		(layer "F.Cu")
		(net "M_B_CPU0_SA_CA<4>")
	)
	(segment
		(start 291.556694 -262.341868)
		(end 291.225986 -262.341868)
		(width 0.101854)
		(layer "F.Cu")
		(net "M_B_CPU0_SA_CA<4>")
	)
	(segment
		(start 289.231578 -262.332978)
		(end 288.62274 -262.332978)
		(width 0.20066)
		(layer "F.Cu")
		(net "M_B_CPU0_SA_CA<4>")
	)
	(segment
		(start 288.305748 -262.978138)
		(end 287.801304 -262.978138)
		(width 0.20066)
		(layer "F.Cu")
		(net "M_B_CPU0_SA_CA<4>")
	)
	(segment
		(start 291.225986 -262.341868)
		(end 289.240468 -262.341868)
		(width 0.1016)
		(layer "F.Cu")
		(net "M_B_CPU0_SA_CA<4>")
	)
	(segment
		(start 287.589976 -262.76681)
		(end 286.255714 -262.76681)
		(width 0.20066)
		(layer "F.Cu")
		(net "M_B_CPU0_SA_CA<4>")
	)
	(segment
		(start 288.46018 -262.823706)
		(end 288.305748 -262.978138)
		(width 0.20066)
		(layer "F.Cu")
		(net "M_B_CPU0_SA_CA<4>")
	)
	(segment
		(start 288.46018 -262.495538)
		(end 288.46018 -262.823706)
		(width 0.20066)
		(layer "F.Cu")
		(net "M_B_CPU0_SA_CA<4>")
	)
	(segment
		(start 293.799514 -262.76681)
		(end 292.160198 -262.76681)
		(width 0.20066)
		(layer "F.Cu")
		(net "M_B_CPU0_SA_CA<4>")
	)
	(segment
		(start 307.748686 -259.512816)
		(end 307.403246 -259.512816)
		(width 0.18288)
		(layer "In2.Cu")
		(net "M_B_CPU0_SA_CA<4>")
	)
	(segment
		(start 331.816202 -253.982474)
		(end 330.474066 -253.982474)
		(width 0.18288)
		(layer "In2.Cu")
		(net "M_B_CPU0_SA_CA<4>")
	)
	(segment
		(start 337.134962 -253.919736)
		(end 336.4103 -254.227838)
		(width 0.088646)
		(layer "In2.Cu")
		(net "M_B_CPU0_SA_CA<4>")
	)
	(segment
		(start 310.35625 -259.084572)
		(end 310.10225 -259.084572)
		(width 0.18288)
		(layer "In2.Cu")
		(net "M_B_CPU0_SA_CA<4>")
	)
	(segment
		(start 320.593974 -256.87401)
		(end 315.52769 -258.972812)
		(width 0.18288)
		(layer "In2.Cu")
		(net "M_B_CPU0_SA_CA<4>")
	)
	(segment
		(start 299.959014 -262.425688)
		(end 299.270928 -262.425688)
		(width 0.18288)
		(layer "In2.Cu")
		(net "M_B_CPU0_SA_CA<4>")
	)
	(segment
		(start 332.435962 -254.29464)
		(end 332.26121 -254.29464)
		(width 0.088646)
		(layer "In2.Cu")
		(net "M_B_CPU0_SA_CA<4>")
	)
	(segment
		(start 298.08678 -262.822436)
		(end 297.923458 -262.985758)
		(width 0.18288)
		(layer "In2.Cu")
		(net "M_B_CPU0_SA_CA<4>")
	)
	(segment
		(start 309.87365 -259.559552)
		(end 309.69966 -259.733542)
		(width 0.18288)
		(layer "In2.Cu")
		(net "M_B_CPU0_SA_CA<4>")
	)
	(segment
		(start 307.969412 -259.733542)
		(end 307.748686 -259.512816)
		(width 0.18288)
		(layer "In2.Cu")
		(net "M_B_CPU0_SA_CA<4>")
	)
	(segment
		(start 311.936638 -259.231384)
		(end 310.503062 -259.231384)
		(width 0.18288)
		(layer "In2.Cu")
		(net "M_B_CPU0_SA_CA<4>")
	)
	(segment
		(start 299.270928 -262.425688)
		(end 299.186854 -262.341614)
		(width 0.18288)
		(layer "In2.Cu")
		(net "M_B_CPU0_SA_CA<4>")
	)
	(segment
		(start 302.875188 -261.266178)
		(end 302.875188 -262.151114)
		(width 0.18288)
		(layer "In2.Cu")
		(net "M_B_CPU0_SA_CA<4>")
	)
	(segment
		(start 327.868534 -256.588006)
		(end 321.284346 -256.588006)
		(width 0.18288)
		(layer "In2.Cu")
		(net "M_B_CPU0_SA_CA<4>")
	)
	(segment
		(start 302.875188 -262.151114)
		(end 302.66513 -262.361172)
		(width 0.18288)
		(layer "In2.Cu")
		(net "M_B_CPU0_SA_CA<4>")
	)
	(segment
		(start 297.487086 -262.985758)
		(end 297.327066 -262.825738)
		(width 0.18288)
		(layer "In2.Cu")
		(net "M_B_CPU0_SA_CA<4>")
	)
	(segment
		(start 312.19521 -258.972812)
		(end 311.936638 -259.231384)
		(width 0.18288)
		(layer "In2.Cu")
		(net "M_B_CPU0_SA_CA<4>")
	)
	(segment
		(start 297.923458 -262.985758)
		(end 297.487086 -262.985758)
		(width 0.18288)
		(layer "In2.Cu")
		(net "M_B_CPU0_SA_CA<4>")
	)
	(segment
		(start 331.949044 -253.982474)
		(end 331.816202 -253.982474)
		(width 0.088646)
		(layer "In2.Cu")
		(net "M_B_CPU0_SA_CA<4>")
	)
	(segment
		(start 299.186854 -262.341614)
		(end 298.247308 -262.341614)
		(width 0.18288)
		(layer "In2.Cu")
		(net "M_B_CPU0_SA_CA<4>")
	)
	(segment
		(start 315.52769 -258.972812)
		(end 312.19521 -258.972812)
		(width 0.18288)
		(layer "In2.Cu")
		(net "M_B_CPU0_SA_CA<4>")
	)
	(segment
		(start 302.66513 -262.361172)
		(end 300.02353 -262.361172)
		(width 0.18288)
		(layer "In2.Cu")
		(net "M_B_CPU0_SA_CA<4>")
	)
	(segment
		(start 336.4103 -254.227838)
		(end 336.38236 -254.244094)
		(width 0.088646)
		(layer "In2.Cu")
		(net "M_B_CPU0_SA_CA<4>")
	)
	(segment
		(start 310.10225 -259.084572)
		(end 309.87365 -259.313172)
		(width 0.18288)
		(layer "In2.Cu")
		(net "M_B_CPU0_SA_CA<4>")
	)
	(segment
		(start 332.26121 -254.29464)
		(end 331.949044 -253.982474)
		(width 0.088646)
		(layer "In2.Cu")
		(net "M_B_CPU0_SA_CA<4>")
	)
	(segment
		(start 303.553114 -260.588252)
		(end 302.875188 -261.266178)
		(width 0.18288)
		(layer "In2.Cu")
		(net "M_B_CPU0_SA_CA<4>")
	)
	(segment
		(start 306.32781 -260.588252)
		(end 303.553114 -260.588252)
		(width 0.18288)
		(layer "In2.Cu")
		(net "M_B_CPU0_SA_CA<4>")
	)
	(segment
		(start 309.69966 -259.733542)
		(end 307.969412 -259.733542)
		(width 0.18288)
		(layer "In2.Cu")
		(net "M_B_CPU0_SA_CA<4>")
	)
	(segment
		(start 298.247308 -262.341614)
		(end 298.08678 -262.502142)
		(width 0.18288)
		(layer "In2.Cu")
		(net "M_B_CPU0_SA_CA<4>")
	)
	(segment
		(start 298.08678 -262.502142)
		(end 298.08678 -262.822436)
		(width 0.18288)
		(layer "In2.Cu")
		(net "M_B_CPU0_SA_CA<4>")
	)
	(segment
		(start 309.87365 -259.313172)
		(end 309.87365 -259.559552)
		(width 0.18288)
		(layer "In2.Cu")
		(net "M_B_CPU0_SA_CA<4>")
	)
	(segment
		(start 297.327066 -262.505444)
		(end 297.017948 -262.196326)
		(width 0.18288)
		(layer "In2.Cu")
		(net "M_B_CPU0_SA_CA<4>")
	)
	(segment
		(start 330.474066 -253.982474)
		(end 327.868534 -256.588006)
		(width 0.18288)
		(layer "In2.Cu")
		(net "M_B_CPU0_SA_CA<4>")
	)
	(segment
		(start 297.017948 -262.196326)
		(end 295.474898 -262.196326)
		(width 0.18288)
		(layer "In2.Cu")
		(net "M_B_CPU0_SA_CA<4>")
	)
	(segment
		(start 310.503062 -259.231384)
		(end 310.35625 -259.084572)
		(width 0.18288)
		(layer "In2.Cu")
		(net "M_B_CPU0_SA_CA<4>")
	)
	(segment
		(start 300.02353 -262.361172)
		(end 299.959014 -262.425688)
		(width 0.18288)
		(layer "In2.Cu")
		(net "M_B_CPU0_SA_CA<4>")
	)
	(segment
		(start 321.284346 -256.588006)
		(end 320.593974 -256.87401)
		(width 0.18288)
		(layer "In2.Cu")
		(net "M_B_CPU0_SA_CA<4>")
	)
	(segment
		(start 297.327066 -262.825738)
		(end 297.327066 -262.505444)
		(width 0.18288)
		(layer "In2.Cu")
		(net "M_B_CPU0_SA_CA<4>")
	)
	(segment
		(start 295.474898 -262.196326)
		(end 294.904414 -262.76681)
		(width 0.18288)
		(layer "In2.Cu")
		(net "M_B_CPU0_SA_CA<4>")
	)
	(segment
		(start 307.403246 -259.512816)
		(end 306.32781 -260.588252)
		(width 0.18288)
		(layer "In2.Cu")
		(net "M_B_CPU0_SA_CA<4>")
	)
	(arc
		(start 335.44256 -254.244094)
		(mid 335.255362 -254.294237)
		(end 335.068164 -254.244094)
		(width 0.088646)
		(layer "In2.Cu")
		(net "M_B_CPU0_SA_CA<4>")
	)
	(arc
		(start 335.068164 -254.244094)
		(mid 334.785462 -254.168318)
		(end 334.50276 -254.244094)
		(width 0.088646)
		(layer "In2.Cu")
		(net "M_B_CPU0_SA_CA<4>")
	)
	(arc
		(start 333.56296 -254.244094)
		(mid 333.375762 -254.294237)
		(end 333.188564 -254.244094)
		(width 0.088646)
		(layer "In2.Cu")
		(net "M_B_CPU0_SA_CA<4>")
	)
	(arc
		(start 336.007964 -254.244094)
		(mid 335.725262 -254.168318)
		(end 335.44256 -254.244094)
		(width 0.088646)
		(layer "In2.Cu")
		(net "M_B_CPU0_SA_CA<4>")
	)
	(arc
		(start 334.128364 -254.244094)
		(mid 333.845662 -254.168318)
		(end 333.56296 -254.244094)
		(width 0.088646)
		(layer "In2.Cu")
		(net "M_B_CPU0_SA_CA<4>")
	)
	(arc
		(start 332.62316 -254.244094)
		(mid 332.532888 -254.281693)
		(end 332.435962 -254.29464)
		(width 0.088646)
		(layer "In2.Cu")
		(net "M_B_CPU0_SA_CA<4>")
	)
	(arc
		(start 333.188564 -254.244094)
		(mid 332.905862 -254.168318)
		(end 332.62316 -254.244094)
		(width 0.088646)
		(layer "In2.Cu")
		(net "M_B_CPU0_SA_CA<4>")
	)
	(arc
		(start 336.38236 -254.244094)
		(mid 336.195162 -254.294237)
		(end 336.007964 -254.244094)
		(width 0.088646)
		(layer "In2.Cu")
		(net "M_B_CPU0_SA_CA<4>")
	)
	(arc
		(start 334.50276 -254.244094)
		(mid 334.315562 -254.294237)
		(end 334.128364 -254.244094)
		(width 0.088646)
		(layer "In2.Cu")
		(net "M_B_CPU0_SA_CA<4>")
	)
	(segment
		(start 295.693846 -263.7409)
		(end 295.693846 -263.892538)
		(width 0.20066)
		(layer "F.Cu")
		(net "M_B_CPU0_SA_CA<3>")
	)
	(segment
		(start 295.000426 -264.041636)
		(end 292.927532 -264.041636)
		(width 0.1016)
		(layer "F.Cu")
		(net "M_B_CPU0_SA_CA<3>")
	)
	(segment
		(start 296.42943 -263.824212)
		(end 296.217594 -263.612376)
		(width 0.20066)
		(layer "F.Cu")
		(net "M_B_CPU0_SA_CA<3>")
	)
	(segment
		(start 292.67531 -264.05586)
		(end 292.321488 -264.05586)
		(width 0.20066)
		(layer "F.Cu")
		(net "M_B_CPU0_SA_CA<3>")
	)
	(segment
		(start 297.08348 -263.616694)
		(end 296.875962 -263.824212)
		(width 0.20066)
		(layer "F.Cu")
		(net "M_B_CPU0_SA_CA<3>")
	)
	(segment
		(start 338.544916 -254.197612)
		(end 338.544916 -254.733298)
		(width 0.20066)
		(layer "F.Cu")
		(net "M_B_CPU0_SA_CA<3>")
	)
	(segment
		(start 292.178994 -263.913366)
		(end 292.178994 -263.742678)
		(width 0.20066)
		(layer "F.Cu")
		(net "M_B_CPU0_SA_CA<3>")
	)
	(segment
		(start 292.05301 -263.616694)
		(end 290.355782 -263.616694)
		(width 0.20066)
		(layer "F.Cu")
		(net "M_B_CPU0_SA_CA<3>")
	)
	(segment
		(start 292.321488 -264.05586)
		(end 292.178994 -263.913366)
		(width 0.20066)
		(layer "F.Cu")
		(net "M_B_CPU0_SA_CA<3>")
	)
	(segment
		(start 299.029882 -263.616694)
		(end 297.899582 -263.616694)
		(width 0.20066)
		(layer "F.Cu")
		(net "M_B_CPU0_SA_CA<3>")
	)
	(segment
		(start 295.82237 -263.612376)
		(end 295.693846 -263.7409)
		(width 0.20066)
		(layer "F.Cu")
		(net "M_B_CPU0_SA_CA<3>")
	)
	(segment
		(start 292.927532 -264.041636)
		(end 292.689534 -264.041636)
		(width 0.101854)
		(layer "F.Cu")
		(net "M_B_CPU0_SA_CA<3>")
	)
	(segment
		(start 296.875962 -263.824212)
		(end 296.42943 -263.824212)
		(width 0.20066)
		(layer "F.Cu")
		(net "M_B_CPU0_SA_CA<3>")
	)
	(segment
		(start 295.544748 -264.041636)
		(end 295.000426 -264.041636)
		(width 0.20066)
		(layer "F.Cu")
		(net "M_B_CPU0_SA_CA<3>")
	)
	(segment
		(start 338.544916 -254.733298)
		(end 338.544662 -254.733552)
		(width 0.20066)
		(layer "F.Cu")
		(net "M_B_CPU0_SA_CA<3>")
	)
	(segment
		(start 295.693846 -263.892538)
		(end 295.544748 -264.041636)
		(width 0.20066)
		(layer "F.Cu")
		(net "M_B_CPU0_SA_CA<3>")
	)
	(segment
		(start 297.899582 -263.616694)
		(end 297.08348 -263.616694)
		(width 0.20066)
		(layer "F.Cu")
		(net "M_B_CPU0_SA_CA<3>")
	)
	(segment
		(start 292.178994 -263.742678)
		(end 292.05301 -263.616694)
		(width 0.20066)
		(layer "F.Cu")
		(net "M_B_CPU0_SA_CA<3>")
	)
	(segment
		(start 292.689534 -264.041636)
		(end 292.67531 -264.05586)
		(width 0.101854)
		(layer "F.Cu")
		(net "M_B_CPU0_SA_CA<3>")
	)
	(segment
		(start 296.217594 -263.612376)
		(end 295.82237 -263.612376)
		(width 0.20066)
		(layer "F.Cu")
		(net "M_B_CPU0_SA_CA<3>")
	)
	(segment
		(start 332.321916 -254.659892)
		(end 332.11643 -254.659892)
		(width 0.088646)
		(layer "In2.Cu")
		(net "M_B_CPU0_SA_CA<3>")
	)
	(segment
		(start 314.082938 -259.490464)
		(end 313.76747 -259.805932)
		(width 0.18288)
		(layer "In2.Cu")
		(net "M_B_CPU0_SA_CA<3>")
	)
	(segment
		(start 299.029882 -263.365234)
		(end 299.029882 -263.616694)
		(width 0.18288)
		(layer "In2.Cu")
		(net "M_B_CPU0_SA_CA<3>")
	)
	(segment
		(start 308.361334 -260.241542)
		(end 308.228238 -260.374638)
		(width 0.18288)
		(layer "In2.Cu")
		(net "M_B_CPU0_SA_CA<3>")
	)
	(segment
		(start 307.15966 -260.650228)
		(end 306.975002 -260.834886)
		(width 0.18288)
		(layer "In2.Cu")
		(net "M_B_CPU0_SA_CA<3>")
	)
	(segment
		(start 338.544662 -254.733552)
		(end 337.82 -254.42545)
		(width 0.088646)
		(layer "In2.Cu")
		(net "M_B_CPU0_SA_CA<3>")
	)
	(segment
		(start 311.355486 -260.109462)
		(end 310.991758 -259.745734)
		(width 0.18288)
		(layer "In2.Cu")
		(net "M_B_CPU0_SA_CA<3>")
	)
	(segment
		(start 314.862718 -259.805932)
		(end 314.632848 -259.805932)
		(width 0.18288)
		(layer "In2.Cu")
		(net "M_B_CPU0_SA_CA<3>")
	)
	(segment
		(start 301.649892 -263.453372)
		(end 301.524416 -263.578848)
		(width 0.18288)
		(layer "In2.Cu")
		(net "M_B_CPU0_SA_CA<3>")
	)
	(segment
		(start 309.344314 -260.64337)
		(end 308.942486 -260.241542)
		(width 0.18288)
		(layer "In2.Cu")
		(net "M_B_CPU0_SA_CA<3>")
	)
	(segment
		(start 331.941424 -254.484886)
		(end 331.816202 -254.484886)
		(width 0.088646)
		(layer "In2.Cu")
		(net "M_B_CPU0_SA_CA<3>")
	)
	(segment
		(start 303.82718 -261.328916)
		(end 303.600612 -261.328916)
		(width 0.18288)
		(layer "In2.Cu")
		(net "M_B_CPU0_SA_CA<3>")
	)
	(segment
		(start 310.991758 -259.745734)
		(end 310.671972 -259.745734)
		(width 0.18288)
		(layer "In2.Cu")
		(net "M_B_CPU0_SA_CA<3>")
	)
	(segment
		(start 308.942486 -260.241542)
		(end 308.361334 -260.241542)
		(width 0.18288)
		(layer "In2.Cu")
		(net "M_B_CPU0_SA_CA<3>")
	)
	(segment
		(start 304.936906 -261.528306)
		(end 304.627788 -261.528306)
		(width 0.18288)
		(layer "In2.Cu")
		(net "M_B_CPU0_SA_CA<3>")
	)
	(segment
		(start 330.460858 -254.484886)
		(end 328.012298 -256.933446)
		(width 0.18288)
		(layer "In2.Cu")
		(net "M_B_CPU0_SA_CA<3>")
	)
	(segment
		(start 305.797458 -261.221474)
		(end 305.675538 -261.099554)
		(width 0.18288)
		(layer "In2.Cu")
		(net "M_B_CPU0_SA_CA<3>")
	)
	(segment
		(start 306.784502 -261.548372)
		(end 305.957478 -261.548372)
		(width 0.18288)
		(layer "In2.Cu")
		(net "M_B_CPU0_SA_CA<3>")
	)
	(segment
		(start 305.957478 -261.548372)
		(end 305.797458 -261.388352)
		(width 0.18288)
		(layer "In2.Cu")
		(net "M_B_CPU0_SA_CA<3>")
	)
	(segment
		(start 303.0982 -262.664956)
		(end 303.0982 -262.802116)
		(width 0.18288)
		(layer "In2.Cu")
		(net "M_B_CPU0_SA_CA<3>")
	)
	(segment
		(start 308.228238 -260.558534)
		(end 307.870606 -260.916166)
		(width 0.18288)
		(layer "In2.Cu")
		(net "M_B_CPU0_SA_CA<3>")
	)
	(segment
		(start 300.942502 -263.453372)
		(end 300.942502 -263.32942)
		(width 0.18288)
		(layer "In2.Cu")
		(net "M_B_CPU0_SA_CA<3>")
	)
	(segment
		(start 303.0982 -262.802116)
		(end 302.777144 -263.123172)
		(width 0.18288)
		(layer "In2.Cu")
		(net "M_B_CPU0_SA_CA<3>")
	)
	(segment
		(start 300.257464 -262.943086)
		(end 299.45203 -262.943086)
		(width 0.18288)
		(layer "In2.Cu")
		(net "M_B_CPU0_SA_CA<3>")
	)
	(segment
		(start 307.676042 -260.916166)
		(end 307.410104 -260.650228)
		(width 0.18288)
		(layer "In2.Cu")
		(net "M_B_CPU0_SA_CA<3>")
	)
	(segment
		(start 300.942502 -263.32942)
		(end 300.782482 -263.1694)
		(width 0.18288)
		(layer "In2.Cu")
		(net "M_B_CPU0_SA_CA<3>")
	)
	(segment
		(start 305.675538 -261.099554)
		(end 305.195478 -261.099554)
		(width 0.18288)
		(layer "In2.Cu")
		(net "M_B_CPU0_SA_CA<3>")
	)
	(segment
		(start 321.797934 -256.933446)
		(end 320.98869 -257.268726)
		(width 0.18288)
		(layer "In2.Cu")
		(net "M_B_CPU0_SA_CA<3>")
	)
	(segment
		(start 307.870606 -260.916166)
		(end 307.676042 -260.916166)
		(width 0.18288)
		(layer "In2.Cu")
		(net "M_B_CPU0_SA_CA<3>")
	)
	(segment
		(start 314.632848 -259.805932)
		(end 314.31738 -259.490464)
		(width 0.18288)
		(layer "In2.Cu")
		(net "M_B_CPU0_SA_CA<3>")
	)
	(segment
		(start 300.483778 -263.1694)
		(end 300.257464 -262.943086)
		(width 0.18288)
		(layer "In2.Cu")
		(net "M_B_CPU0_SA_CA<3>")
	)
	(segment
		(start 301.649892 -263.283192)
		(end 301.649892 -263.453372)
		(width 0.18288)
		(layer "In2.Cu")
		(net "M_B_CPU0_SA_CA<3>")
	)
	(segment
		(start 332.11643 -254.659892)
		(end 331.941424 -254.484886)
		(width 0.088646)
		(layer "In2.Cu")
		(net "M_B_CPU0_SA_CA<3>")
	)
	(segment
		(start 320.98869 -257.268726)
		(end 314.862718 -259.805932)
		(width 0.18288)
		(layer "In2.Cu")
		(net "M_B_CPU0_SA_CA<3>")
	)
	(segment
		(start 304.627788 -261.528306)
		(end 304.47742 -261.678674)
		(width 0.18288)
		(layer "In2.Cu")
		(net "M_B_CPU0_SA_CA<3>")
	)
	(segment
		(start 310.671972 -259.745734)
		(end 310.418734 -259.998972)
		(width 0.18288)
		(layer "In2.Cu")
		(net "M_B_CPU0_SA_CA<3>")
	)
	(segment
		(start 332.500478 -254.48133)
		(end 332.321916 -254.659892)
		(width 0.088646)
		(layer "In2.Cu")
		(net "M_B_CPU0_SA_CA<3>")
	)
	(segment
		(start 306.975002 -261.357872)
		(end 306.784502 -261.548372)
		(width 0.18288)
		(layer "In2.Cu")
		(net "M_B_CPU0_SA_CA<3>")
	)
	(segment
		(start 310.418734 -259.998972)
		(end 310.418734 -260.393688)
		(width 0.18288)
		(layer "In2.Cu")
		(net "M_B_CPU0_SA_CA<3>")
	)
	(segment
		(start 299.45203 -262.943086)
		(end 299.029882 -263.365234)
		(width 0.18288)
		(layer "In2.Cu")
		(net "M_B_CPU0_SA_CA<3>")
	)
	(segment
		(start 331.816202 -254.484886)
		(end 330.460858 -254.484886)
		(width 0.18288)
		(layer "In2.Cu")
		(net "M_B_CPU0_SA_CA<3>")
	)
	(segment
		(start 328.012298 -256.933446)
		(end 321.797934 -256.933446)
		(width 0.18288)
		(layer "In2.Cu")
		(net "M_B_CPU0_SA_CA<3>")
	)
	(segment
		(start 301.524416 -263.578848)
		(end 301.067978 -263.578848)
		(width 0.18288)
		(layer "In2.Cu")
		(net "M_B_CPU0_SA_CA<3>")
	)
	(segment
		(start 306.975002 -260.834886)
		(end 306.975002 -261.357872)
		(width 0.18288)
		(layer "In2.Cu")
		(net "M_B_CPU0_SA_CA<3>")
	)
	(segment
		(start 302.777144 -263.123172)
		(end 301.809912 -263.123172)
		(width 0.18288)
		(layer "In2.Cu")
		(net "M_B_CPU0_SA_CA<3>")
	)
	(segment
		(start 313.76747 -259.805932)
		(end 312.059066 -259.805932)
		(width 0.18288)
		(layer "In2.Cu")
		(net "M_B_CPU0_SA_CA<3>")
	)
	(segment
		(start 303.389538 -262.373618)
		(end 303.0982 -262.664956)
		(width 0.18288)
		(layer "In2.Cu")
		(net "M_B_CPU0_SA_CA<3>")
	)
	(segment
		(start 304.176938 -261.678674)
		(end 303.82718 -261.328916)
		(width 0.18288)
		(layer "In2.Cu")
		(net "M_B_CPU0_SA_CA<3>")
	)
	(segment
		(start 308.228238 -260.374638)
		(end 308.228238 -260.558534)
		(width 0.18288)
		(layer "In2.Cu")
		(net "M_B_CPU0_SA_CA<3>")
	)
	(segment
		(start 305.195478 -261.099554)
		(end 305.073558 -261.221474)
		(width 0.18288)
		(layer "In2.Cu")
		(net "M_B_CPU0_SA_CA<3>")
	)
	(segment
		(start 310.418734 -260.393688)
		(end 310.169052 -260.64337)
		(width 0.18288)
		(layer "In2.Cu")
		(net "M_B_CPU0_SA_CA<3>")
	)
	(segment
		(start 337.82 -254.42545)
		(end 337.79206 -254.409194)
		(width 0.088646)
		(layer "In2.Cu")
		(net "M_B_CPU0_SA_CA<3>")
	)
	(segment
		(start 301.067978 -263.578848)
		(end 300.942502 -263.453372)
		(width 0.18288)
		(layer "In2.Cu")
		(net "M_B_CPU0_SA_CA<3>")
	)
	(segment
		(start 312.059066 -259.805932)
		(end 311.755536 -260.109462)
		(width 0.18288)
		(layer "In2.Cu")
		(net "M_B_CPU0_SA_CA<3>")
	)
	(segment
		(start 314.31738 -259.490464)
		(end 314.082938 -259.490464)
		(width 0.18288)
		(layer "In2.Cu")
		(net "M_B_CPU0_SA_CA<3>")
	)
	(segment
		(start 305.797458 -261.388352)
		(end 305.797458 -261.221474)
		(width 0.18288)
		(layer "In2.Cu")
		(net "M_B_CPU0_SA_CA<3>")
	)
	(segment
		(start 300.782482 -263.1694)
		(end 300.483778 -263.1694)
		(width 0.18288)
		(layer "In2.Cu")
		(net "M_B_CPU0_SA_CA<3>")
	)
	(segment
		(start 311.755536 -260.109462)
		(end 311.355486 -260.109462)
		(width 0.18288)
		(layer "In2.Cu")
		(net "M_B_CPU0_SA_CA<3>")
	)
	(segment
		(start 310.169052 -260.64337)
		(end 309.344314 -260.64337)
		(width 0.18288)
		(layer "In2.Cu")
		(net "M_B_CPU0_SA_CA<3>")
	)
	(segment
		(start 304.47742 -261.678674)
		(end 304.176938 -261.678674)
		(width 0.18288)
		(layer "In2.Cu")
		(net "M_B_CPU0_SA_CA<3>")
	)
	(segment
		(start 305.073558 -261.391654)
		(end 304.936906 -261.528306)
		(width 0.18288)
		(layer "In2.Cu")
		(net "M_B_CPU0_SA_CA<3>")
	)
	(segment
		(start 307.410104 -260.650228)
		(end 307.15966 -260.650228)
		(width 0.18288)
		(layer "In2.Cu")
		(net "M_B_CPU0_SA_CA<3>")
	)
	(segment
		(start 305.073558 -261.221474)
		(end 305.073558 -261.391654)
		(width 0.18288)
		(layer "In2.Cu")
		(net "M_B_CPU0_SA_CA<3>")
	)
	(segment
		(start 303.600612 -261.328916)
		(end 303.389538 -261.53999)
		(width 0.18288)
		(layer "In2.Cu")
		(net "M_B_CPU0_SA_CA<3>")
	)
	(segment
		(start 303.389538 -261.53999)
		(end 303.389538 -262.373618)
		(width 0.18288)
		(layer "In2.Cu")
		(net "M_B_CPU0_SA_CA<3>")
	)
	(segment
		(start 301.809912 -263.123172)
		(end 301.649892 -263.283192)
		(width 0.18288)
		(layer "In2.Cu")
		(net "M_B_CPU0_SA_CA<3>")
	)
	(arc
		(start 335.538064 -254.409194)
		(mid 335.255362 -254.48497)
		(end 334.97266 -254.409194)
		(width 0.088646)
		(layer "In2.Cu")
		(net "M_B_CPU0_SA_CA<3>")
	)
	(arc
		(start 334.97266 -254.409194)
		(mid 334.785462 -254.359051)
		(end 334.598264 -254.409194)
		(width 0.088646)
		(layer "In2.Cu")
		(net "M_B_CPU0_SA_CA<3>")
	)
	(arc
		(start 332.718664 -254.409194)
		(mid 332.61327 -254.45644)
		(end 332.500478 -254.48133)
		(width 0.088646)
		(layer "In2.Cu")
		(net "M_B_CPU0_SA_CA<3>")
	)
	(arc
		(start 333.658464 -254.409194)
		(mid 333.375762 -254.48497)
		(end 333.09306 -254.409194)
		(width 0.088646)
		(layer "In2.Cu")
		(net "M_B_CPU0_SA_CA<3>")
	)
	(arc
		(start 336.85226 -254.409194)
		(mid 336.665062 -254.359051)
		(end 336.477864 -254.409194)
		(width 0.088646)
		(layer "In2.Cu")
		(net "M_B_CPU0_SA_CA<3>")
	)
	(arc
		(start 334.598264 -254.409194)
		(mid 334.315562 -254.48497)
		(end 334.03286 -254.409194)
		(width 0.088646)
		(layer "In2.Cu")
		(net "M_B_CPU0_SA_CA<3>")
	)
	(arc
		(start 334.03286 -254.409194)
		(mid 333.845662 -254.359051)
		(end 333.658464 -254.409194)
		(width 0.088646)
		(layer "In2.Cu")
		(net "M_B_CPU0_SA_CA<3>")
	)
	(arc
		(start 337.79206 -254.409194)
		(mid 337.604862 -254.359051)
		(end 337.417664 -254.409194)
		(width 0.088646)
		(layer "In2.Cu")
		(net "M_B_CPU0_SA_CA<3>")
	)
	(arc
		(start 337.417664 -254.409194)
		(mid 337.134962 -254.48497)
		(end 336.85226 -254.409194)
		(width 0.088646)
		(layer "In2.Cu")
		(net "M_B_CPU0_SA_CA<3>")
	)
	(arc
		(start 333.09306 -254.409194)
		(mid 332.905862 -254.359051)
		(end 332.718664 -254.409194)
		(width 0.088646)
		(layer "In2.Cu")
		(net "M_B_CPU0_SA_CA<3>")
	)
	(arc
		(start 335.91246 -254.409194)
		(mid 335.725262 -254.359051)
		(end 335.538064 -254.409194)
		(width 0.088646)
		(layer "In2.Cu")
		(net "M_B_CPU0_SA_CA<3>")
	)
	(arc
		(start 336.477864 -254.409194)
		(mid 336.195162 -254.48497)
		(end 335.91246 -254.409194)
		(width 0.088646)
		(layer "In2.Cu")
		(net "M_B_CPU0_SA_CA<3>")
	)
	(segment
		(start 336.665316 -254.197612)
		(end 336.665316 -254.733298)
		(width 0.20066)
		(layer "F.Cu")
		(net "M_B_CPU0_SA_CA<2>")
	)
	(segment
		(start 289.240468 -264.041636)
		(end 289.231578 -264.032746)
		(width 0.1016)
		(layer "F.Cu")
		(net "M_B_CPU0_SA_CA<2>")
	)
	(segment
		(start 287.801304 -264.677906)
		(end 287.589976 -264.466578)
		(width 0.20066)
		(layer "F.Cu")
		(net "M_B_CPU0_SA_CA<2>")
	)
	(segment
		(start 288.305748 -264.677906)
		(end 287.801304 -264.677906)
		(width 0.20066)
		(layer "F.Cu")
		(net "M_B_CPU0_SA_CA<2>")
	)
	(segment
		(start 291.225986 -264.041636)
		(end 289.240468 -264.041636)
		(width 0.1016)
		(layer "F.Cu")
		(net "M_B_CPU0_SA_CA<2>")
	)
	(segment
		(start 291.556694 -264.041636)
		(end 291.225986 -264.041636)
		(width 0.101854)
		(layer "F.Cu")
		(net "M_B_CPU0_SA_CA<2>")
	)
	(segment
		(start 288.46018 -264.195306)
		(end 288.46018 -264.523474)
		(width 0.20066)
		(layer "F.Cu")
		(net "M_B_CPU0_SA_CA<2>")
	)
	(segment
		(start 292.160198 -264.466578)
		(end 291.735256 -264.041636)
		(width 0.20066)
		(layer "F.Cu")
		(net "M_B_CPU0_SA_CA<2>")
	)
	(segment
		(start 291.735256 -264.041636)
		(end 291.556694 -264.041636)
		(width 0.20066)
		(layer "F.Cu")
		(net "M_B_CPU0_SA_CA<2>")
	)
	(segment
		(start 336.665316 -254.733298)
		(end 336.665062 -254.733552)
		(width 0.20066)
		(layer "F.Cu")
		(net "M_B_CPU0_SA_CA<2>")
	)
	(segment
		(start 294.904414 -264.466578)
		(end 293.799514 -264.466578)
		(width 0.20066)
		(layer "F.Cu")
		(net "M_B_CPU0_SA_CA<2>")
	)
	(segment
		(start 288.62274 -264.032746)
		(end 288.46018 -264.195306)
		(width 0.20066)
		(layer "F.Cu")
		(net "M_B_CPU0_SA_CA<2>")
	)
	(segment
		(start 287.589976 -264.466578)
		(end 286.255714 -264.466578)
		(width 0.20066)
		(layer "F.Cu")
		(net "M_B_CPU0_SA_CA<2>")
	)
	(segment
		(start 293.799514 -264.466578)
		(end 292.160198 -264.466578)
		(width 0.20066)
		(layer "F.Cu")
		(net "M_B_CPU0_SA_CA<2>")
	)
	(segment
		(start 288.46018 -264.523474)
		(end 288.305748 -264.677906)
		(width 0.20066)
		(layer "F.Cu")
		(net "M_B_CPU0_SA_CA<2>")
	)
	(segment
		(start 289.231578 -264.032746)
		(end 288.62274 -264.032746)
		(width 0.20066)
		(layer "F.Cu")
		(net "M_B_CPU0_SA_CA<2>")
	)
	(segment
		(start 295.78046 -262.906256)
		(end 295.62044 -263.066276)
		(width 0.18288)
		(layer "In2.Cu")
		(net "M_B_CPU0_SA_CA<2>")
	)
	(segment
		(start 309.749698 -261.469124)
		(end 307.595778 -261.469124)
		(width 0.18288)
		(layer "In2.Cu")
		(net "M_B_CPU0_SA_CA<2>")
	)
	(segment
		(start 296.367962 -263.750552)
		(end 296.367962 -263.09955)
		(width 0.18288)
		(layer "In2.Cu")
		(net "M_B_CPU0_SA_CA<2>")
	)
	(segment
		(start 298.062396 -264.469372)
		(end 297.59275 -264.469372)
		(width 0.18288)
		(layer "In2.Cu")
		(net "M_B_CPU0_SA_CA<2>")
	)
	(segment
		(start 298.490132 -264.041636)
		(end 298.062396 -264.469372)
		(width 0.18288)
		(layer "In2.Cu")
		(net "M_B_CPU0_SA_CA<2>")
	)
	(segment
		(start 297.59275 -264.469372)
		(end 297.03395 -263.910572)
		(width 0.18288)
		(layer "In2.Cu")
		(net "M_B_CPU0_SA_CA<2>")
	)
	(segment
		(start 332.435962 -254.982218)
		(end 332.052422 -254.982218)
		(width 0.088646)
		(layer "In2.Cu")
		(net "M_B_CPU0_SA_CA<2>")
	)
	(segment
		(start 310.90235 -260.628892)
		(end 310.334152 -261.19709)
		(width 0.18288)
		(layer "In2.Cu")
		(net "M_B_CPU0_SA_CA<2>")
	)
	(segment
		(start 331.964792 -254.894588)
		(end 331.816202 -254.894588)
		(width 0.088646)
		(layer "In2.Cu")
		(net "M_B_CPU0_SA_CA<2>")
	)
	(segment
		(start 328.156062 -257.278886)
		(end 322.311776 -257.278886)
		(width 0.18288)
		(layer "In2.Cu")
		(net "M_B_CPU0_SA_CA<2>")
	)
	(segment
		(start 330.54036 -254.894588)
		(end 328.156062 -257.278886)
		(width 0.18288)
		(layer "In2.Cu")
		(net "M_B_CPU0_SA_CA<2>")
	)
	(segment
		(start 303.812448 -262.861298)
		(end 302.585374 -264.088372)
		(width 0.18288)
		(layer "In2.Cu")
		(net "M_B_CPU0_SA_CA<2>")
	)
	(segment
		(start 331.816202 -254.894588)
		(end 330.54036 -254.894588)
		(width 0.18288)
		(layer "In2.Cu")
		(net "M_B_CPU0_SA_CA<2>")
	)
	(segment
		(start 295.62044 -263.066276)
		(end 295.62044 -263.750552)
		(width 0.18288)
		(layer "In2.Cu")
		(net "M_B_CPU0_SA_CA<2>")
	)
	(segment
		(start 313.727084 -260.628892)
		(end 310.90235 -260.628892)
		(width 0.18288)
		(layer "In2.Cu")
		(net "M_B_CPU0_SA_CA<2>")
	)
	(segment
		(start 303.812448 -262.666988)
		(end 303.812448 -262.861298)
		(width 0.18288)
		(layer "In2.Cu")
		(net "M_B_CPU0_SA_CA<2>")
	)
	(segment
		(start 322.311776 -257.278886)
		(end 321.383152 -257.663188)
		(width 0.18288)
		(layer "In2.Cu")
		(net "M_B_CPU0_SA_CA<2>")
	)
	(segment
		(start 299.555154 -263.826244)
		(end 299.339762 -264.041636)
		(width 0.18288)
		(layer "In2.Cu")
		(net "M_B_CPU0_SA_CA<2>")
	)
	(segment
		(start 321.383152 -257.663188)
		(end 314.777882 -260.397498)
		(width 0.18288)
		(layer "In2.Cu")
		(net "M_B_CPU0_SA_CA<2>")
	)
	(segment
		(start 296.527982 -263.910572)
		(end 296.367962 -263.750552)
		(width 0.18288)
		(layer "In2.Cu")
		(net "M_B_CPU0_SA_CA<2>")
	)
	(segment
		(start 299.339762 -264.041636)
		(end 298.490132 -264.041636)
		(width 0.18288)
		(layer "In2.Cu")
		(net "M_B_CPU0_SA_CA<2>")
	)
	(segment
		(start 295.62044 -263.750552)
		(end 294.904414 -264.466578)
		(width 0.18288)
		(layer "In2.Cu")
		(net "M_B_CPU0_SA_CA<2>")
	)
	(segment
		(start 307.595778 -261.469124)
		(end 306.747164 -262.317738)
		(width 0.18288)
		(layer "In2.Cu")
		(net "M_B_CPU0_SA_CA<2>")
	)
	(segment
		(start 336.665062 -254.733552)
		(end 335.941162 -255.0414)
		(width 0.088646)
		(layer "In2.Cu")
		(net "M_B_CPU0_SA_CA<2>")
	)
	(segment
		(start 335.91246 -255.058164)
		(end 335.91246 -255.05791)
		(width 0.088646)
		(layer "In2.Cu")
		(net "M_B_CPU0_SA_CA<2>")
	)
	(segment
		(start 296.367962 -263.09955)
		(end 296.174668 -262.906256)
		(width 0.18288)
		(layer "In2.Cu")
		(net "M_B_CPU0_SA_CA<2>")
	)
	(segment
		(start 300.090586 -264.088372)
		(end 299.828458 -263.826244)
		(width 0.18288)
		(layer "In2.Cu")
		(net "M_B_CPU0_SA_CA<2>")
	)
	(segment
		(start 310.021732 -261.19709)
		(end 309.749698 -261.469124)
		(width 0.18288)
		(layer "In2.Cu")
		(net "M_B_CPU0_SA_CA<2>")
	)
	(segment
		(start 310.334152 -261.19709)
		(end 310.021732 -261.19709)
		(width 0.18288)
		(layer "In2.Cu")
		(net "M_B_CPU0_SA_CA<2>")
	)
	(segment
		(start 299.828458 -263.826244)
		(end 299.555154 -263.826244)
		(width 0.18288)
		(layer "In2.Cu")
		(net "M_B_CPU0_SA_CA<2>")
	)
	(segment
		(start 314.777882 -260.397498)
		(end 313.958478 -260.397498)
		(width 0.18288)
		(layer "In2.Cu")
		(net "M_B_CPU0_SA_CA<2>")
	)
	(segment
		(start 296.174668 -262.906256)
		(end 295.78046 -262.906256)
		(width 0.18288)
		(layer "In2.Cu")
		(net "M_B_CPU0_SA_CA<2>")
	)
	(segment
		(start 297.03395 -263.910572)
		(end 296.527982 -263.910572)
		(width 0.18288)
		(layer "In2.Cu")
		(net "M_B_CPU0_SA_CA<2>")
	)
	(segment
		(start 332.052422 -254.982218)
		(end 331.964792 -254.894588)
		(width 0.088646)
		(layer "In2.Cu")
		(net "M_B_CPU0_SA_CA<2>")
	)
	(segment
		(start 335.941162 -255.0414)
		(end 335.91246 -255.058164)
		(width 0.088646)
		(layer "In2.Cu")
		(net "M_B_CPU0_SA_CA<2>")
	)
	(segment
		(start 304.161698 -262.317738)
		(end 303.812448 -262.666988)
		(width 0.18288)
		(layer "In2.Cu")
		(net "M_B_CPU0_SA_CA<2>")
	)
	(segment
		(start 313.958478 -260.397498)
		(end 313.727084 -260.628892)
		(width 0.18288)
		(layer "In2.Cu")
		(net "M_B_CPU0_SA_CA<2>")
	)
	(segment
		(start 302.585374 -264.088372)
		(end 300.090586 -264.088372)
		(width 0.18288)
		(layer "In2.Cu")
		(net "M_B_CPU0_SA_CA<2>")
	)
	(segment
		(start 306.747164 -262.317738)
		(end 304.161698 -262.317738)
		(width 0.18288)
		(layer "In2.Cu")
		(net "M_B_CPU0_SA_CA<2>")
	)
	(arc
		(start 333.09306 -255.05791)
		(mid 332.905862 -255.108053)
		(end 332.718664 -255.05791)
		(width 0.088646)
		(layer "In2.Cu")
		(net "M_B_CPU0_SA_CA<2>")
	)
	(arc
		(start 334.03286 -255.05791)
		(mid 333.845662 -255.108053)
		(end 333.658464 -255.05791)
		(width 0.088646)
		(layer "In2.Cu")
		(net "M_B_CPU0_SA_CA<2>")
	)
	(arc
		(start 332.718664 -255.05791)
		(mid 332.582298 -255.001432)
		(end 332.435962 -254.982218)
		(width 0.088646)
		(layer "In2.Cu")
		(net "M_B_CPU0_SA_CA<2>")
	)
	(arc
		(start 335.91246 -255.05791)
		(mid 335.725262 -255.108053)
		(end 335.538064 -255.05791)
		(width 0.088646)
		(layer "In2.Cu")
		(net "M_B_CPU0_SA_CA<2>")
	)
	(arc
		(start 333.658464 -255.05791)
		(mid 333.375762 -254.982168)
		(end 333.09306 -255.05791)
		(width 0.088646)
		(layer "In2.Cu")
		(net "M_B_CPU0_SA_CA<2>")
	)
	(arc
		(start 334.598264 -255.05791)
		(mid 334.315562 -254.982168)
		(end 334.03286 -255.05791)
		(width 0.088646)
		(layer "In2.Cu")
		(net "M_B_CPU0_SA_CA<2>")
	)
	(arc
		(start 335.538064 -255.05791)
		(mid 335.255362 -254.982168)
		(end 334.97266 -255.05791)
		(width 0.088646)
		(layer "In2.Cu")
		(net "M_B_CPU0_SA_CA<2>")
	)
	(arc
		(start 334.97266 -255.05791)
		(mid 334.785462 -255.108053)
		(end 334.598264 -255.05791)
		(width 0.088646)
		(layer "In2.Cu")
		(net "M_B_CPU0_SA_CA<2>")
	)
	(segment
		(start 292.321488 -265.755882)
		(end 292.178994 -265.613388)
		(width 0.20066)
		(layer "F.Cu")
		(net "M_B_CPU0_SA_CA<1>")
	)
	(segment
		(start 292.178994 -265.613388)
		(end 292.178994 -265.4427)
		(width 0.20066)
		(layer "F.Cu")
		(net "M_B_CPU0_SA_CA<1>")
	)
	(segment
		(start 296.875962 -265.524234)
		(end 296.42943 -265.524234)
		(width 0.20066)
		(layer "F.Cu")
		(net "M_B_CPU0_SA_CA<1>")
	)
	(segment
		(start 296.42943 -265.524234)
		(end 296.217594 -265.312398)
		(width 0.20066)
		(layer "F.Cu")
		(net "M_B_CPU0_SA_CA<1>")
	)
	(segment
		(start 292.689534 -265.741658)
		(end 292.67531 -265.755882)
		(width 0.101854)
		(layer "F.Cu")
		(net "M_B_CPU0_SA_CA<1>")
	)
	(segment
		(start 297.899582 -265.316716)
		(end 297.08348 -265.316716)
		(width 0.20066)
		(layer "F.Cu")
		(net "M_B_CPU0_SA_CA<1>")
	)
	(segment
		(start 292.67531 -265.755882)
		(end 292.321488 -265.755882)
		(width 0.20066)
		(layer "F.Cu")
		(net "M_B_CPU0_SA_CA<1>")
	)
	(segment
		(start 297.08348 -265.316716)
		(end 296.875962 -265.524234)
		(width 0.20066)
		(layer "F.Cu")
		(net "M_B_CPU0_SA_CA<1>")
	)
	(segment
		(start 292.927532 -265.741658)
		(end 292.689534 -265.741658)
		(width 0.101854)
		(layer "F.Cu")
		(net "M_B_CPU0_SA_CA<1>")
	)
	(segment
		(start 295.693846 -265.59256)
		(end 295.544748 -265.741658)
		(width 0.20066)
		(layer "F.Cu")
		(net "M_B_CPU0_SA_CA<1>")
	)
	(segment
		(start 296.217594 -265.312398)
		(end 295.82237 -265.312398)
		(width 0.20066)
		(layer "F.Cu")
		(net "M_B_CPU0_SA_CA<1>")
	)
	(segment
		(start 339.014562 -255.011682)
		(end 339.014562 -255.547368)
		(width 0.20066)
		(layer "F.Cu")
		(net "M_B_CPU0_SA_CA<1>")
	)
	(segment
		(start 292.05301 -265.316716)
		(end 290.355782 -265.316716)
		(width 0.20066)
		(layer "F.Cu")
		(net "M_B_CPU0_SA_CA<1>")
	)
	(segment
		(start 295.000426 -265.741658)
		(end 292.927532 -265.741658)
		(width 0.1016)
		(layer "F.Cu")
		(net "M_B_CPU0_SA_CA<1>")
	)
	(segment
		(start 295.544748 -265.741658)
		(end 295.000426 -265.741658)
		(width 0.20066)
		(layer "F.Cu")
		(net "M_B_CPU0_SA_CA<1>")
	)
	(segment
		(start 299.029882 -265.316716)
		(end 297.899582 -265.316716)
		(width 0.20066)
		(layer "F.Cu")
		(net "M_B_CPU0_SA_CA<1>")
	)
	(segment
		(start 295.82237 -265.312398)
		(end 295.693846 -265.440922)
		(width 0.20066)
		(layer "F.Cu")
		(net "M_B_CPU0_SA_CA<1>")
	)
	(segment
		(start 292.178994 -265.4427)
		(end 292.05301 -265.316716)
		(width 0.20066)
		(layer "F.Cu")
		(net "M_B_CPU0_SA_CA<1>")
	)
	(segment
		(start 339.014562 -255.547368)
		(end 339.014816 -255.547622)
		(width 0.20066)
		(layer "F.Cu")
		(net "M_B_CPU0_SA_CA<1>")
	)
	(segment
		(start 295.693846 -265.440922)
		(end 295.693846 -265.59256)
		(width 0.20066)
		(layer "F.Cu")
		(net "M_B_CPU0_SA_CA<1>")
	)
	(segment
		(start 311.59704 -261.52221)
		(end 311.309004 -261.234682)
		(width 0.18288)
		(layer "In2.Cu")
		(net "M_B_CPU0_SA_CA<1>")
	)
	(segment
		(start 339.014816 -255.547622)
		(end 338.29117 -255.240028)
		(width 0.088646)
		(layer "In2.Cu")
		(net "M_B_CPU0_SA_CA<1>")
	)
	(segment
		(start 300.766988 -265.243056)
		(end 300.559978 -265.036046)
		(width 0.18288)
		(layer "In2.Cu")
		(net "M_B_CPU0_SA_CA<1>")
	)
	(segment
		(start 299.693584 -264.600944)
		(end 299.428408 -264.86612)
		(width 0.18288)
		(layer "In2.Cu")
		(net "M_B_CPU0_SA_CA<1>")
	)
	(segment
		(start 300.305216 -264.600944)
		(end 299.693584 -264.600944)
		(width 0.18288)
		(layer "In2.Cu")
		(net "M_B_CPU0_SA_CA<1>")
	)
	(segment
		(start 303.333912 -264.341864)
		(end 302.825404 -264.850372)
		(width 0.18288)
		(layer "In2.Cu")
		(net "M_B_CPU0_SA_CA<1>")
	)
	(segment
		(start 303.333912 -264.222992)
		(end 303.333912 -264.341864)
		(width 0.18288)
		(layer "In2.Cu")
		(net "M_B_CPU0_SA_CA<1>")
	)
	(segment
		(start 310.937402 -262.357362)
		(end 310.67629 -262.618982)
		(width 0.18288)
		(layer "In2.Cu")
		(net "M_B_CPU0_SA_CA<1>")
	)
	(segment
		(start 304.459894 -263.255252)
		(end 304.14849 -263.255252)
		(width 0.18288)
		(layer "In2.Cu")
		(net "M_B_CPU0_SA_CA<1>")
	)
	(segment
		(start 310.937148 -262.08482)
		(end 310.937402 -262.357362)
		(width 0.18288)
		(layer "In2.Cu")
		(net "M_B_CPU0_SA_CA<1>")
	)
	(segment
		(start 300.559978 -264.855706)
		(end 300.305216 -264.600944)
		(width 0.18288)
		(layer "In2.Cu")
		(net "M_B_CPU0_SA_CA<1>")
	)
	(segment
		(start 299.029882 -265.024108)
		(end 299.029882 -265.316716)
		(width 0.18288)
		(layer "In2.Cu")
		(net "M_B_CPU0_SA_CA<1>")
	)
	(segment
		(start 322.39331 -257.624326)
		(end 322.093336 -257.9243)
		(width 0.18288)
		(layer "In2.Cu")
		(net "M_B_CPU0_SA_CA<1>")
	)
	(segment
		(start 301.91837 -265.243056)
		(end 300.766988 -265.243056)
		(width 0.18288)
		(layer "In2.Cu")
		(net "M_B_CPU0_SA_CA<1>")
	)
	(segment
		(start 302.311054 -264.850372)
		(end 301.91837 -265.243056)
		(width 0.18288)
		(layer "In2.Cu")
		(net "M_B_CPU0_SA_CA<1>")
	)
	(segment
		(start 314.588906 -261.02564)
		(end 314.422282 -261.4295)
		(width 0.18288)
		(layer "In2.Cu")
		(net "M_B_CPU0_SA_CA<1>")
	)
	(segment
		(start 328.299318 -257.624326)
		(end 322.39331 -257.624326)
		(width 0.18288)
		(layer "In2.Cu")
		(net "M_B_CPU0_SA_CA<1>")
	)
	(segment
		(start 312.506868 -261.52221)
		(end 311.59704 -261.52221)
		(width 0.18288)
		(layer "In2.Cu")
		(net "M_B_CPU0_SA_CA<1>")
	)
	(segment
		(start 308.041548 -262.386572)
		(end 307.654706 -262.386572)
		(width 0.18288)
		(layer "In2.Cu")
		(net "M_B_CPU0_SA_CA<1>")
	)
	(segment
		(start 314.422282 -261.4295)
		(end 314.198 -261.52221)
		(width 0.18288)
		(layer "In2.Cu")
		(net "M_B_CPU0_SA_CA<1>")
	)
	(segment
		(start 306.434236 -263.333992)
		(end 305.925982 -262.825738)
		(width 0.18288)
		(layer "In2.Cu")
		(net "M_B_CPU0_SA_CA<1>")
	)
	(segment
		(start 299.428408 -264.86612)
		(end 299.18787 -264.86612)
		(width 0.18288)
		(layer "In2.Cu")
		(net "M_B_CPU0_SA_CA<1>")
	)
	(segment
		(start 332.060296 -255.272032)
		(end 331.816202 -255.272032)
		(width 0.088646)
		(layer "In2.Cu")
		(net "M_B_CPU0_SA_CA<1>")
	)
	(segment
		(start 299.18787 -264.86612)
		(end 299.029882 -265.024108)
		(width 0.18288)
		(layer "In2.Cu")
		(net "M_B_CPU0_SA_CA<1>")
	)
	(segment
		(start 310.67629 -262.618982)
		(end 309.897018 -262.618982)
		(width 0.18288)
		(layer "In2.Cu")
		(net "M_B_CPU0_SA_CA<1>")
	)
	(segment
		(start 314.198 -261.52221)
		(end 313.591194 -261.52221)
		(width 0.18288)
		(layer "In2.Cu")
		(net "M_B_CPU0_SA_CA<1>")
	)
	(segment
		(start 310.69788 -261.573772)
		(end 310.698134 -261.846314)
		(width 0.18288)
		(layer "In2.Cu")
		(net "M_B_CPU0_SA_CA<1>")
	)
	(segment
		(start 337.332828 -255.22936)
		(end 337.322414 -255.223264)
		(width 0.088646)
		(layer "In2.Cu")
		(net "M_B_CPU0_SA_CA<1>")
	)
	(segment
		(start 338.29117 -255.240028)
		(end 338.26196 -255.223264)
		(width 0.088646)
		(layer "In2.Cu")
		(net "M_B_CPU0_SA_CA<1>")
	)
	(segment
		(start 309.664608 -262.386572)
		(end 309.112158 -262.386572)
		(width 0.18288)
		(layer "In2.Cu")
		(net "M_B_CPU0_SA_CA<1>")
	)
	(segment
		(start 307.654706 -262.386572)
		(end 306.707286 -263.333992)
		(width 0.18288)
		(layer "In2.Cu")
		(net "M_B_CPU0_SA_CA<1>")
	)
	(segment
		(start 306.707286 -263.333992)
		(end 306.434236 -263.333992)
		(width 0.18288)
		(layer "In2.Cu")
		(net "M_B_CPU0_SA_CA<1>")
	)
	(segment
		(start 322.093336 -257.9243)
		(end 314.588906 -261.02564)
		(width 0.18288)
		(layer "In2.Cu")
		(net "M_B_CPU0_SA_CA<1>")
	)
	(segment
		(start 330.651612 -255.272032)
		(end 328.299318 -257.624326)
		(width 0.18288)
		(layer "In2.Cu")
		(net "M_B_CPU0_SA_CA<1>")
	)
	(segment
		(start 336.392774 -255.22936)
		(end 336.38236 -255.223264)
		(width 0.088646)
		(layer "In2.Cu")
		(net "M_B_CPU0_SA_CA<1>")
	)
	(segment
		(start 305.925982 -262.825738)
		(end 304.889408 -262.825738)
		(width 0.18288)
		(layer "In2.Cu")
		(net "M_B_CPU0_SA_CA<1>")
	)
	(segment
		(start 304.14849 -263.255252)
		(end 303.333404 -264.070338)
		(width 0.18288)
		(layer "In2.Cu")
		(net "M_B_CPU0_SA_CA<1>")
	)
	(segment
		(start 313.210448 -261.141464)
		(end 312.887614 -261.141464)
		(width 0.18288)
		(layer "In2.Cu")
		(net "M_B_CPU0_SA_CA<1>")
	)
	(segment
		(start 309.897018 -262.618982)
		(end 309.664608 -262.386572)
		(width 0.18288)
		(layer "In2.Cu")
		(net "M_B_CPU0_SA_CA<1>")
	)
	(segment
		(start 332.159864 -255.172464)
		(end 332.060296 -255.272032)
		(width 0.088646)
		(layer "In2.Cu")
		(net "M_B_CPU0_SA_CA<1>")
	)
	(segment
		(start 312.887614 -261.141464)
		(end 312.506868 -261.52221)
		(width 0.18288)
		(layer "In2.Cu")
		(net "M_B_CPU0_SA_CA<1>")
	)
	(segment
		(start 310.698134 -261.846314)
		(end 310.937148 -262.08482)
		(width 0.18288)
		(layer "In2.Cu")
		(net "M_B_CPU0_SA_CA<1>")
	)
	(segment
		(start 308.408578 -262.019542)
		(end 308.041548 -262.386572)
		(width 0.18288)
		(layer "In2.Cu")
		(net "M_B_CPU0_SA_CA<1>")
	)
	(segment
		(start 303.333404 -264.070338)
		(end 303.333912 -264.222992)
		(width 0.18288)
		(layer "In2.Cu")
		(net "M_B_CPU0_SA_CA<1>")
	)
	(segment
		(start 304.889408 -262.825738)
		(end 304.459894 -263.255252)
		(width 0.18288)
		(layer "In2.Cu")
		(net "M_B_CPU0_SA_CA<1>")
	)
	(segment
		(start 308.745128 -262.019542)
		(end 308.408578 -262.019542)
		(width 0.18288)
		(layer "In2.Cu")
		(net "M_B_CPU0_SA_CA<1>")
	)
	(segment
		(start 302.825404 -264.850372)
		(end 302.311054 -264.850372)
		(width 0.18288)
		(layer "In2.Cu")
		(net "M_B_CPU0_SA_CA<1>")
	)
	(segment
		(start 309.112158 -262.386572)
		(end 308.745128 -262.019542)
		(width 0.18288)
		(layer "In2.Cu")
		(net "M_B_CPU0_SA_CA<1>")
	)
	(segment
		(start 331.816202 -255.272032)
		(end 330.651612 -255.272032)
		(width 0.18288)
		(layer "In2.Cu")
		(net "M_B_CPU0_SA_CA<1>")
	)
	(segment
		(start 332.435962 -255.172464)
		(end 332.159864 -255.172464)
		(width 0.088646)
		(layer "In2.Cu")
		(net "M_B_CPU0_SA_CA<1>")
	)
	(segment
		(start 300.559978 -265.036046)
		(end 300.559978 -264.855706)
		(width 0.18288)
		(layer "In2.Cu")
		(net "M_B_CPU0_SA_CA<1>")
	)
	(segment
		(start 313.591194 -261.52221)
		(end 313.210448 -261.141464)
		(width 0.18288)
		(layer "In2.Cu")
		(net "M_B_CPU0_SA_CA<1>")
	)
	(segment
		(start 311.0357 -261.234936)
		(end 310.69788 -261.573772)
		(width 0.18288)
		(layer "In2.Cu")
		(net "M_B_CPU0_SA_CA<1>")
	)
	(segment
		(start 311.309004 -261.234682)
		(end 311.0357 -261.234936)
		(width 0.18288)
		(layer "In2.Cu")
		(net "M_B_CPU0_SA_CA<1>")
	)
	(arc
		(start 336.007964 -255.223264)
		(mid 335.725262 -255.299006)
		(end 335.44256 -255.223264)
		(width 0.088646)
		(layer "In2.Cu")
		(net "M_B_CPU0_SA_CA<1>")
	)
	(arc
		(start 334.128364 -255.223264)
		(mid 333.845662 -255.299006)
		(end 333.56296 -255.223264)
		(width 0.088646)
		(layer "In2.Cu")
		(net "M_B_CPU0_SA_CA<1>")
	)
	(arc
		(start 332.62316 -255.223264)
		(mid 332.532904 -255.185542)
		(end 332.435962 -255.172464)
		(width 0.088646)
		(layer "In2.Cu")
		(net "M_B_CPU0_SA_CA<1>")
	)
	(arc
		(start 335.068164 -255.223264)
		(mid 334.785462 -255.299006)
		(end 334.50276 -255.223264)
		(width 0.088646)
		(layer "In2.Cu")
		(net "M_B_CPU0_SA_CA<1>")
	)
	(arc
		(start 337.887564 -255.223264)
		(mid 337.611005 -255.298973)
		(end 337.332828 -255.22936)
		(width 0.088646)
		(layer "In2.Cu")
		(net "M_B_CPU0_SA_CA<1>")
	)
	(arc
		(start 337.322414 -255.223264)
		(mid 337.135216 -255.173121)
		(end 336.948018 -255.223264)
		(width 0.088646)
		(layer "In2.Cu")
		(net "M_B_CPU0_SA_CA<1>")
	)
	(arc
		(start 333.188564 -255.223264)
		(mid 332.905862 -255.299006)
		(end 332.62316 -255.223264)
		(width 0.088646)
		(layer "In2.Cu")
		(net "M_B_CPU0_SA_CA<1>")
	)
	(arc
		(start 336.38236 -255.223264)
		(mid 336.195162 -255.173121)
		(end 336.007964 -255.223264)
		(width 0.088646)
		(layer "In2.Cu")
		(net "M_B_CPU0_SA_CA<1>")
	)
	(arc
		(start 336.948018 -255.223264)
		(mid 336.671205 -255.2991)
		(end 336.392774 -255.22936)
		(width 0.088646)
		(layer "In2.Cu")
		(net "M_B_CPU0_SA_CA<1>")
	)
	(arc
		(start 338.26196 -255.223264)
		(mid 338.074762 -255.173121)
		(end 337.887564 -255.223264)
		(width 0.088646)
		(layer "In2.Cu")
		(net "M_B_CPU0_SA_CA<1>")
	)
	(arc
		(start 333.56296 -255.223264)
		(mid 333.375762 -255.173121)
		(end 333.188564 -255.223264)
		(width 0.088646)
		(layer "In2.Cu")
		(net "M_B_CPU0_SA_CA<1>")
	)
	(arc
		(start 335.44256 -255.223264)
		(mid 335.255362 -255.173121)
		(end 335.068164 -255.223264)
		(width 0.088646)
		(layer "In2.Cu")
		(net "M_B_CPU0_SA_CA<1>")
	)
	(arc
		(start 334.50276 -255.223264)
		(mid 334.315562 -255.173121)
		(end 334.128364 -255.223264)
		(width 0.088646)
		(layer "In2.Cu")
		(net "M_B_CPU0_SA_CA<1>")
	)
	(segment
		(start 287.589976 -266.1666)
		(end 286.255714 -266.1666)
		(width 0.20066)
		(layer "F.Cu")
		(net "M_B_CPU0_SA_CA<0>")
	)
	(segment
		(start 293.799514 -266.1666)
		(end 292.160198 -266.1666)
		(width 0.20066)
		(layer "F.Cu")
		(net "M_B_CPU0_SA_CA<0>")
	)
	(segment
		(start 294.904414 -266.1666)
		(end 293.799514 -266.1666)
		(width 0.20066)
		(layer "F.Cu")
		(net "M_B_CPU0_SA_CA<0>")
	)
	(segment
		(start 291.735256 -265.741658)
		(end 291.556694 -265.741658)
		(width 0.20066)
		(layer "F.Cu")
		(net "M_B_CPU0_SA_CA<0>")
	)
	(segment
		(start 288.305748 -266.377928)
		(end 287.801304 -266.377928)
		(width 0.20066)
		(layer "F.Cu")
		(net "M_B_CPU0_SA_CA<0>")
	)
	(segment
		(start 288.46018 -266.223496)
		(end 288.305748 -266.377928)
		(width 0.20066)
		(layer "F.Cu")
		(net "M_B_CPU0_SA_CA<0>")
	)
	(segment
		(start 288.46018 -265.895328)
		(end 288.46018 -266.223496)
		(width 0.20066)
		(layer "F.Cu")
		(net "M_B_CPU0_SA_CA<0>")
	)
	(segment
		(start 291.225986 -265.741658)
		(end 289.240468 -265.741658)
		(width 0.1016)
		(layer "F.Cu")
		(net "M_B_CPU0_SA_CA<0>")
	)
	(segment
		(start 336.195162 -255.011682)
		(end 336.195162 -255.547622)
		(width 0.20066)
		(layer "F.Cu")
		(net "M_B_CPU0_SA_CA<0>")
	)
	(segment
		(start 288.62274 -265.732768)
		(end 288.46018 -265.895328)
		(width 0.20066)
		(layer "F.Cu")
		(net "M_B_CPU0_SA_CA<0>")
	)
	(segment
		(start 292.160198 -266.1666)
		(end 291.735256 -265.741658)
		(width 0.20066)
		(layer "F.Cu")
		(net "M_B_CPU0_SA_CA<0>")
	)
	(segment
		(start 289.231578 -265.732768)
		(end 288.62274 -265.732768)
		(width 0.20066)
		(layer "F.Cu")
		(net "M_B_CPU0_SA_CA<0>")
	)
	(segment
		(start 291.556694 -265.741658)
		(end 291.225986 -265.741658)
		(width 0.101854)
		(layer "F.Cu")
		(net "M_B_CPU0_SA_CA<0>")
	)
	(segment
		(start 287.801304 -266.377928)
		(end 287.589976 -266.1666)
		(width 0.20066)
		(layer "F.Cu")
		(net "M_B_CPU0_SA_CA<0>")
	)
	(segment
		(start 289.240468 -265.741658)
		(end 289.231578 -265.732768)
		(width 0.1016)
		(layer "F.Cu")
		(net "M_B_CPU0_SA_CA<0>")
	)
	(segment
		(start 311.750456 -262.295132)
		(end 310.96458 -263.081008)
		(width 0.18288)
		(layer "In2.Cu")
		(net "M_B_CPU0_SA_CA<0>")
	)
	(segment
		(start 330.698348 -255.713992)
		(end 328.442574 -257.969766)
		(width 0.18288)
		(layer "In2.Cu")
		(net "M_B_CPU0_SA_CA<0>")
	)
	(segment
		(start 314.216796 -262.082788)
		(end 313.998864 -262.082788)
		(width 0.18288)
		(layer "In2.Cu")
		(net "M_B_CPU0_SA_CA<0>")
	)
	(segment
		(start 306.76977 -264.001504)
		(end 304.177954 -264.001504)
		(width 0.18288)
		(layer "In2.Cu")
		(net "M_B_CPU0_SA_CA<0>")
	)
	(segment
		(start 302.636682 -265.7602)
		(end 300.089316 -265.7602)
		(width 0.18288)
		(layer "In2.Cu")
		(net "M_B_CPU0_SA_CA<0>")
	)
	(segment
		(start 296.274236 -264.78865)
		(end 296.089578 -264.603992)
		(width 0.18288)
		(layer "In2.Cu")
		(net "M_B_CPU0_SA_CA<0>")
	)
	(segment
		(start 295.396158 -264.797032)
		(end 295.396158 -265.24712)
		(width 0.18288)
		(layer "In2.Cu")
		(net "M_B_CPU0_SA_CA<0>")
	)
	(segment
		(start 299.303694 -265.741658)
		(end 297.087036 -265.741658)
		(width 0.18288)
		(layer "In2.Cu")
		(net "M_B_CPU0_SA_CA<0>")
	)
	(segment
		(start 310.798972 -263.149588)
		(end 307.621686 -263.149588)
		(width 0.18288)
		(layer "In2.Cu")
		(net "M_B_CPU0_SA_CA<0>")
	)
	(segment
		(start 303.893728 -264.503154)
		(end 302.636682 -265.7602)
		(width 0.18288)
		(layer "In2.Cu")
		(net "M_B_CPU0_SA_CA<0>")
	)
	(segment
		(start 300.089316 -265.7602)
		(end 299.699172 -265.598656)
		(width 0.18288)
		(layer "In2.Cu")
		(net "M_B_CPU0_SA_CA<0>")
	)
	(segment
		(start 295.589198 -264.603992)
		(end 295.396158 -264.797032)
		(width 0.18288)
		(layer "In2.Cu")
		(net "M_B_CPU0_SA_CA<0>")
	)
	(segment
		(start 304.177954 -264.001504)
		(end 303.893728 -264.28573)
		(width 0.18288)
		(layer "In2.Cu")
		(net "M_B_CPU0_SA_CA<0>")
	)
	(segment
		(start 295.162478 -265.811508)
		(end 295.093644 -265.97737)
		(width 0.18288)
		(layer "In2.Cu")
		(net "M_B_CPU0_SA_CA<0>")
	)
	(segment
		(start 314.802266 -261.840218)
		(end 314.216796 -262.082788)
		(width 0.18288)
		(layer "In2.Cu")
		(net "M_B_CPU0_SA_CA<0>")
	)
	(segment
		(start 296.434256 -265.446002)
		(end 296.274236 -265.285982)
		(width 0.18288)
		(layer "In2.Cu")
		(net "M_B_CPU0_SA_CA<0>")
	)
	(segment
		(start 303.893728 -264.28573)
		(end 303.893728 -264.503154)
		(width 0.18288)
		(layer "In2.Cu")
		(net "M_B_CPU0_SA_CA<0>")
	)
	(segment
		(start 295.093644 -265.97737)
		(end 294.904414 -266.1666)
		(width 0.18288)
		(layer "In2.Cu")
		(net "M_B_CPU0_SA_CA<0>")
	)
	(segment
		(start 299.446696 -265.598656)
		(end 299.303694 -265.741658)
		(width 0.18288)
		(layer "In2.Cu")
		(net "M_B_CPU0_SA_CA<0>")
	)
	(segment
		(start 307.621686 -263.149588)
		(end 306.76977 -264.001504)
		(width 0.18288)
		(layer "In2.Cu")
		(net "M_B_CPU0_SA_CA<0>")
	)
	(segment
		(start 336.195162 -255.547622)
		(end 336.351626 -255.81864)
		(width 0.088646)
		(layer "In2.Cu")
		(net "M_B_CPU0_SA_CA<0>")
	)
	(segment
		(start 332.013306 -255.713992)
		(end 331.816202 -255.713992)
		(width 0.088646)
		(layer "In2.Cu")
		(net "M_B_CPU0_SA_CA<0>")
	)
	(segment
		(start 314.975494 -261.422388)
		(end 314.802266 -261.840218)
		(width 0.18288)
		(layer "In2.Cu")
		(net "M_B_CPU0_SA_CA<0>")
	)
	(segment
		(start 322.074794 -258.48183)
		(end 314.975494 -261.422388)
		(width 0.18288)
		(layer "In2.Cu")
		(net "M_B_CPU0_SA_CA<0>")
	)
	(segment
		(start 322.586858 -257.969766)
		(end 322.074794 -258.48183)
		(width 0.18288)
		(layer "In2.Cu")
		(net "M_B_CPU0_SA_CA<0>")
	)
	(segment
		(start 331.816202 -255.713992)
		(end 330.698348 -255.713992)
		(width 0.18288)
		(layer "In2.Cu")
		(net "M_B_CPU0_SA_CA<0>")
	)
	(segment
		(start 295.396158 -265.24712)
		(end 295.162478 -265.811508)
		(width 0.18288)
		(layer "In2.Cu")
		(net "M_B_CPU0_SA_CA<0>")
	)
	(segment
		(start 299.699172 -265.598656)
		(end 299.446696 -265.598656)
		(width 0.18288)
		(layer "In2.Cu")
		(net "M_B_CPU0_SA_CA<0>")
	)
	(segment
		(start 296.089578 -264.603992)
		(end 295.589198 -264.603992)
		(width 0.18288)
		(layer "In2.Cu")
		(net "M_B_CPU0_SA_CA<0>")
	)
	(segment
		(start 328.442574 -257.969766)
		(end 322.586858 -257.969766)
		(width 0.18288)
		(layer "In2.Cu")
		(net "M_B_CPU0_SA_CA<0>")
	)
	(segment
		(start 297.087036 -265.741658)
		(end 296.79138 -265.446002)
		(width 0.18288)
		(layer "In2.Cu")
		(net "M_B_CPU0_SA_CA<0>")
	)
	(segment
		(start 332.22184 -255.922526)
		(end 332.013306 -255.713992)
		(width 0.088646)
		(layer "In2.Cu")
		(net "M_B_CPU0_SA_CA<0>")
	)
	(segment
		(start 310.96458 -263.081008)
		(end 310.798972 -263.149588)
		(width 0.18288)
		(layer "In2.Cu")
		(net "M_B_CPU0_SA_CA<0>")
	)
	(segment
		(start 313.78652 -262.295132)
		(end 311.750456 -262.295132)
		(width 0.18288)
		(layer "In2.Cu")
		(net "M_B_CPU0_SA_CA<0>")
	)
	(segment
		(start 336.351626 -255.81864)
		(end 336.330544 -255.896618)
		(width 0.088646)
		(layer "In2.Cu")
		(net "M_B_CPU0_SA_CA<0>")
	)
	(segment
		(start 296.79138 -265.446002)
		(end 296.434256 -265.446002)
		(width 0.18288)
		(layer "In2.Cu")
		(net "M_B_CPU0_SA_CA<0>")
	)
	(segment
		(start 332.435962 -255.922526)
		(end 332.22184 -255.922526)
		(width 0.088646)
		(layer "In2.Cu")
		(net "M_B_CPU0_SA_CA<0>")
	)
	(segment
		(start 313.998864 -262.082788)
		(end 313.78652 -262.295132)
		(width 0.18288)
		(layer "In2.Cu")
		(net "M_B_CPU0_SA_CA<0>")
	)
	(segment
		(start 296.274236 -265.285982)
		(end 296.274236 -264.78865)
		(width 0.18288)
		(layer "In2.Cu")
		(net "M_B_CPU0_SA_CA<0>")
	)
	(arc
		(start 334.128364 -255.87198)
		(mid 333.845662 -255.796204)
		(end 333.56296 -255.87198)
		(width 0.088646)
		(layer "In2.Cu")
		(net "M_B_CPU0_SA_CA<0>")
	)
	(arc
		(start 332.62316 -255.87198)
		(mid 332.532888 -255.909579)
		(end 332.435962 -255.922526)
		(width 0.088646)
		(layer "In2.Cu")
		(net "M_B_CPU0_SA_CA<0>")
	)
	(arc
		(start 335.44256 -255.87198)
		(mid 335.255362 -255.922123)
		(end 335.068164 -255.87198)
		(width 0.088646)
		(layer "In2.Cu")
		(net "M_B_CPU0_SA_CA<0>")
	)
	(arc
		(start 336.330544 -255.896618)
		(mid 336.166448 -255.920965)
		(end 336.007964 -255.87198)
		(width 0.088646)
		(layer "In2.Cu")
		(net "M_B_CPU0_SA_CA<0>")
	)
	(arc
		(start 334.50276 -255.87198)
		(mid 334.315562 -255.922123)
		(end 334.128364 -255.87198)
		(width 0.088646)
		(layer "In2.Cu")
		(net "M_B_CPU0_SA_CA<0>")
	)
	(arc
		(start 333.56296 -255.87198)
		(mid 333.375762 -255.922123)
		(end 333.188564 -255.87198)
		(width 0.088646)
		(layer "In2.Cu")
		(net "M_B_CPU0_SA_CA<0>")
	)
	(arc
		(start 336.007964 -255.87198)
		(mid 335.725262 -255.796204)
		(end 335.44256 -255.87198)
		(width 0.088646)
		(layer "In2.Cu")
		(net "M_B_CPU0_SA_CA<0>")
	)
	(arc
		(start 333.188564 -255.87198)
		(mid 332.905862 -255.796204)
		(end 332.62316 -255.87198)
		(width 0.088646)
		(layer "In2.Cu")
		(net "M_B_CPU0_SA_CA<0>")
	)
	(arc
		(start 335.068164 -255.87198)
		(mid 334.785462 -255.796204)
		(end 334.50276 -255.87198)
		(width 0.088646)
		(layer "In2.Cu")
		(net "M_B_CPU0_SA_CA<0>")
	)
	(segment
		(start 299.029882 -260.21665)
		(end 297.899582 -260.21665)
		(width 0.20066)
		(layer "F.Cu")
		(net "M_B_CPU0_CLK_DP<1>")
	)
	(segment
		(start 342.19388 -250.15571)
		(end 342.19388 -249.620024)
		(width 0.20066)
		(layer "F.Cu")
		(net "M_B_CPU0_CLK_DP<1>")
	)
	(segment
		(start 342.194134 -250.155964)
		(end 342.19388 -250.15571)
		(width 0.20066)
		(layer "F.Cu")
		(net "M_B_CPU0_CLK_DP<1>")
	)
	(segment
		(start 312.670444 -256.534666)
		(end 307.081428 -256.534666)
		(width 0.18288)
		(layer "In2.Cu")
		(net "M_B_CPU0_CLK_DP<1>")
	)
	(segment
		(start 299.430694 -259.680202)
		(end 299.029882 -260.081014)
		(width 0.18288)
		(layer "In2.Cu")
		(net "M_B_CPU0_CLK_DP<1>")
	)
	(segment
		(start 341.88146 -250.46559)
		(end 341.592408 -250.754896)
		(width 0.18288)
		(layer "In2.Cu")
		(net "M_B_CPU0_CLK_DP<1>")
	)
	(segment
		(start 342.19388 -249.620024)
		(end 341.88146 -249.932444)
		(width 0.18288)
		(layer "In2.Cu")
		(net "M_B_CPU0_CLK_DP<1>")
	)
	(segment
		(start 334.998822 -251.568712)
		(end 334.302354 -251.857002)
		(width 0.18288)
		(layer "In2.Cu")
		(net "M_B_CPU0_CLK_DP<1>")
	)
	(segment
		(start 339.627464 -251.568712)
		(end 334.998822 -251.568712)
		(width 0.18288)
		(layer "In2.Cu")
		(net "M_B_CPU0_CLK_DP<1>")
	)
	(segment
		(start 341.88146 -249.932444)
		(end 341.88146 -250.46559)
		(width 0.18288)
		(layer "In2.Cu")
		(net "M_B_CPU0_CLK_DP<1>")
	)
	(segment
		(start 299.7835 -259.166106)
		(end 299.672502 -259.434838)
		(width 0.18288)
		(layer "In2.Cu")
		(net "M_B_CPU0_CLK_DP<1>")
	)
	(segment
		(start 299.430694 -259.676646)
		(end 299.430694 -259.680202)
		(width 0.18288)
		(layer "In2.Cu")
		(net "M_B_CPU0_CLK_DP<1>")
	)
	(segment
		(start 341.592408 -250.754896)
		(end 339.627464 -251.568712)
		(width 0.18288)
		(layer "In2.Cu")
		(net "M_B_CPU0_CLK_DP<1>")
	)
	(segment
		(start 318.975232 -255.280922)
		(end 312.670444 -256.534666)
		(width 0.18288)
		(layer "In2.Cu")
		(net "M_B_CPU0_CLK_DP<1>")
	)
	(segment
		(start 334.302354 -251.857002)
		(end 330.643484 -251.857002)
		(width 0.18288)
		(layer "In2.Cu")
		(net "M_B_CPU0_CLK_DP<1>")
	)
	(segment
		(start 307.081428 -256.534666)
		(end 300.531022 -257.941064)
		(width 0.18288)
		(layer "In2.Cu")
		(net "M_B_CPU0_CLK_DP<1>")
	)
	(segment
		(start 299.029882 -260.081014)
		(end 299.029882 -260.21665)
		(width 0.18288)
		(layer "In2.Cu")
		(net "M_B_CPU0_CLK_DP<1>")
	)
	(segment
		(start 330.643484 -251.857002)
		(end 327.29424 -255.206246)
		(width 0.18288)
		(layer "In2.Cu")
		(net "M_B_CPU0_CLK_DP<1>")
	)
	(segment
		(start 319.35039 -255.206246)
		(end 318.975232 -255.280922)
		(width 0.18288)
		(layer "In2.Cu")
		(net "M_B_CPU0_CLK_DP<1>")
	)
	(segment
		(start 300.531022 -257.941064)
		(end 299.956728 -258.136644)
		(width 0.18288)
		(layer "In2.Cu")
		(net "M_B_CPU0_CLK_DP<1>")
	)
	(segment
		(start 327.29424 -255.206246)
		(end 319.35039 -255.206246)
		(width 0.18288)
		(layer "In2.Cu")
		(net "M_B_CPU0_CLK_DP<1>")
	)
	(segment
		(start 299.7835 -258.378198)
		(end 299.7835 -259.166106)
		(width 0.18288)
		(layer "In2.Cu")
		(net "M_B_CPU0_CLK_DP<1>")
	)
	(segment
		(start 299.672502 -259.434838)
		(end 299.430694 -259.676646)
		(width 0.18288)
		(layer "In2.Cu")
		(net "M_B_CPU0_CLK_DP<1>")
	)
	(segment
		(start 299.956728 -258.136644)
		(end 299.7835 -258.378198)
		(width 0.18288)
		(layer "In2.Cu")
		(net "M_B_CPU0_CLK_DP<1>")
	)
	(segment
		(start 340.314534 -250.155964)
		(end 340.314534 -249.620278)
		(width 0.20066)
		(layer "F.Cu")
		(net "M_B_CPU0_CLK_DP<0>")
	)
	(segment
		(start 291.460682 -260.21665)
		(end 290.355782 -260.21665)
		(width 0.20066)
		(layer "F.Cu")
		(net "M_B_CPU0_CLK_DP<0>")
	)
	(segment
		(start 340.314534 -249.620278)
		(end 340.31428 -249.620024)
		(width 0.20066)
		(layer "F.Cu")
		(net "M_B_CPU0_CLK_DP<0>")
	)
	(segment
		(start 317.089536 -254.540512)
		(end 311.390538 -255.696466)
		(width 0.18288)
		(layer "In2.Cu")
		(net "M_B_CPU0_CLK_DP<0>")
	)
	(segment
		(start 335.190592 -250.684792)
		(end 334.002126 -251.177044)
		(width 0.18288)
		(layer "In2.Cu")
		(net "M_B_CPU0_CLK_DP<0>")
	)
	(segment
		(start 330.38161 -251.177044)
		(end 327.018142 -254.540512)
		(width 0.18288)
		(layer "In2.Cu")
		(net "M_B_CPU0_CLK_DP<0>")
	)
	(segment
		(start 292.253924 -258.18211)
		(end 292.253924 -258.710176)
		(width 0.18288)
		(layer "In2.Cu")
		(net "M_B_CPU0_CLK_DP<0>")
	)
	(segment
		(start 339.411564 -250.684792)
		(end 335.190592 -250.684792)
		(width 0.18288)
		(layer "In2.Cu")
		(net "M_B_CPU0_CLK_DP<0>")
	)
	(segment
		(start 291.711634 -259.965698)
		(end 291.460682 -260.21665)
		(width 0.18288)
		(layer "In2.Cu")
		(net "M_B_CPU0_CLK_DP<0>")
	)
	(segment
		(start 292.525196 -259.58546)
		(end 292.144958 -259.965698)
		(width 0.18288)
		(layer "In2.Cu")
		(net "M_B_CPU0_CLK_DP<0>")
	)
	(segment
		(start 311.390538 -255.696466)
		(end 306.187602 -255.696466)
		(width 0.18288)
		(layer "In2.Cu")
		(net "M_B_CPU0_CLK_DP<0>")
	)
	(segment
		(start 292.144958 -259.965698)
		(end 291.711634 -259.965698)
		(width 0.18288)
		(layer "In2.Cu")
		(net "M_B_CPU0_CLK_DP<0>")
	)
	(segment
		(start 334.002126 -251.177044)
		(end 330.38161 -251.177044)
		(width 0.18288)
		(layer "In2.Cu")
		(net "M_B_CPU0_CLK_DP<0>")
	)
	(segment
		(start 327.018142 -254.540512)
		(end 317.089536 -254.540512)
		(width 0.18288)
		(layer "In2.Cu")
		(net "M_B_CPU0_CLK_DP<0>")
	)
	(segment
		(start 339.98789 -250.306586)
		(end 339.749638 -250.544838)
		(width 0.18288)
		(layer "In2.Cu")
		(net "M_B_CPU0_CLK_DP<0>")
	)
	(segment
		(start 340.31428 -249.620024)
		(end 339.98789 -249.946414)
		(width 0.18288)
		(layer "In2.Cu")
		(net "M_B_CPU0_CLK_DP<0>")
	)
	(segment
		(start 306.187602 -255.696466)
		(end 296.868088 -257.612642)
		(width 0.18288)
		(layer "In2.Cu")
		(net "M_B_CPU0_CLK_DP<0>")
	)
	(segment
		(start 296.868088 -257.612642)
		(end 292.823392 -257.612642)
		(width 0.18288)
		(layer "In2.Cu")
		(net "M_B_CPU0_CLK_DP<0>")
	)
	(segment
		(start 339.749638 -250.544838)
		(end 339.411564 -250.684792)
		(width 0.18288)
		(layer "In2.Cu")
		(net "M_B_CPU0_CLK_DP<0>")
	)
	(segment
		(start 292.253924 -258.710176)
		(end 292.525196 -258.981448)
		(width 0.18288)
		(layer "In2.Cu")
		(net "M_B_CPU0_CLK_DP<0>")
	)
	(segment
		(start 292.525196 -258.981448)
		(end 292.525196 -259.58546)
		(width 0.18288)
		(layer "In2.Cu")
		(net "M_B_CPU0_CLK_DP<0>")
	)
	(segment
		(start 292.823392 -257.612642)
		(end 292.253924 -258.18211)
		(width 0.18288)
		(layer "In2.Cu")
		(net "M_B_CPU0_CLK_DP<0>")
	)
	(segment
		(start 339.98789 -249.946414)
		(end 339.98789 -250.306586)
		(width 0.18288)
		(layer "In2.Cu")
		(net "M_B_CPU0_CLK_DP<0>")
	)
	(segment
		(start 341.254334 -250.155964)
		(end 341.254334 -249.620278)
		(width 0.20066)
		(layer "F.Cu")
		(net "M_B_CPU0_CLK_DN<1>")
	)
	(segment
		(start 341.254334 -249.620278)
		(end 341.25408 -249.620024)
		(width 0.20066)
		(layer "F.Cu")
		(net "M_B_CPU0_CLK_DN<1>")
	)
	(segment
		(start 299.029882 -259.366766)
		(end 297.899582 -259.366766)
		(width 0.20066)
		(layer "F.Cu")
		(net "M_B_CPU0_CLK_DN<1>")
	)
	(segment
		(start 305.477672 -256.43713)
		(end 304.955702 -256.549144)
		(width 0.18288)
		(layer "In2.Cu")
		(net "M_B_CPU0_CLK_DN<1>")
	)
	(segment
		(start 316.248796 -255.382522)
		(end 316.153038 -255.526032)
		(width 0.18288)
		(layer "In2.Cu")
		(net "M_B_CPU0_CLK_DN<1>")
	)
	(segment
		(start 305.622452 -256.530856)
		(end 305.477672 -256.43713)
		(width 0.18288)
		(layer "In2.Cu")
		(net "M_B_CPU0_CLK_DN<1>")
	)
	(segment
		(start 304.195988 -256.712212)
		(end 303.674018 -256.824226)
		(width 0.18288)
		(layer "In2.Cu")
		(net "M_B_CPU0_CLK_DN<1>")
	)
	(segment
		(start 334.240632 -251.547122)
		(end 330.51496 -251.547122)
		(width 0.18288)
		(layer "In2.Cu")
		(net "M_B_CPU0_CLK_DN<1>")
	)
	(segment
		(start 327.165716 -254.896366)
		(end 319.319656 -254.896366)
		(width 0.18288)
		(layer "In2.Cu")
		(net "M_B_CPU0_CLK_DN<1>")
	)
	(segment
		(start 307.048408 -256.224786)
		(end 305.622452 -256.530856)
		(width 0.18288)
		(layer "In2.Cu")
		(net "M_B_CPU0_CLK_DN<1>")
	)
	(segment
		(start 330.51496 -251.547122)
		(end 327.165716 -254.896366)
		(width 0.18288)
		(layer "In2.Cu")
		(net "M_B_CPU0_CLK_DN<1>")
	)
	(segment
		(start 303.580546 -256.96926)
		(end 303.059084 -257.08102)
		(width 0.18288)
		(layer "In2.Cu")
		(net "M_B_CPU0_CLK_DN<1>")
	)
	(segment
		(start 299.762672 -257.875278)
		(end 299.47362 -258.278376)
		(width 0.18288)
		(layer "In2.Cu")
		(net "M_B_CPU0_CLK_DN<1>")
	)
	(segment
		(start 313.677808 -255.894078)
		(end 313.589924 -256.02565)
		(width 0.18288)
		(layer "In2.Cu")
		(net "M_B_CPU0_CLK_DN<1>")
	)
	(segment
		(start 301.017178 -257.519678)
		(end 300.448218 -257.641852)
		(width 0.18288)
		(layer "In2.Cu")
		(net "M_B_CPU0_CLK_DN<1>")
	)
	(segment
		(start 339.565742 -251.258832)
		(end 334.9371 -251.258832)
		(width 0.18288)
		(layer "In2.Cu")
		(net "M_B_CPU0_CLK_DN<1>")
	)
	(segment
		(start 340.92388 -250.695968)
		(end 340.764622 -250.630182)
		(width 0.18288)
		(layer "In2.Cu")
		(net "M_B_CPU0_CLK_DN<1>")
	)
	(segment
		(start 312.63971 -256.224786)
		(end 307.048408 -256.224786)
		(width 0.18288)
		(layer "In2.Cu")
		(net "M_B_CPU0_CLK_DN<1>")
	)
	(segment
		(start 316.77229 -255.278382)
		(end 316.248796 -255.382522)
		(width 0.18288)
		(layer "In2.Cu")
		(net "M_B_CPU0_CLK_DN<1>")
	)
	(segment
		(start 299.47362 -259.104384)
		(end 299.409612 -259.259324)
		(width 0.18288)
		(layer "In2.Cu")
		(net "M_B_CPU0_CLK_DN<1>")
	)
	(segment
		(start 301.7774 -257.356356)
		(end 301.63262 -257.262884)
		(width 0.18288)
		(layer "In2.Cu")
		(net "M_B_CPU0_CLK_DN<1>")
	)
	(segment
		(start 302.392334 -257.099562)
		(end 302.298862 -257.244596)
		(width 0.18288)
		(layer "In2.Cu")
		(net "M_B_CPU0_CLK_DN<1>")
	)
	(segment
		(start 318.936116 -254.972566)
		(end 316.915546 -255.37414)
		(width 0.18288)
		(layer "In2.Cu")
		(net "M_B_CPU0_CLK_DN<1>")
	)
	(segment
		(start 304.86223 -256.694178)
		(end 304.340768 -256.805938)
		(width 0.18288)
		(layer "In2.Cu")
		(net "M_B_CPU0_CLK_DN<1>")
	)
	(segment
		(start 314.201048 -255.789938)
		(end 313.677808 -255.894078)
		(width 0.18288)
		(layer "In2.Cu")
		(net "M_B_CPU0_CLK_DN<1>")
	)
	(segment
		(start 313.58078 -256.032254)
		(end 313.577224 -256.038096)
		(width 0.18288)
		(layer "In2.Cu")
		(net "M_B_CPU0_CLK_DN<1>")
	)
	(segment
		(start 316.915546 -255.37414)
		(end 316.77229 -255.278382)
		(width 0.18288)
		(layer "In2.Cu")
		(net "M_B_CPU0_CLK_DN<1>")
	)
	(segment
		(start 301.63262 -257.262884)
		(end 301.110904 -257.374644)
		(width 0.18288)
		(layer "In2.Cu")
		(net "M_B_CPU0_CLK_DN<1>")
	)
	(segment
		(start 301.110904 -257.374644)
		(end 301.017178 -257.519678)
		(width 0.18288)
		(layer "In2.Cu")
		(net "M_B_CPU0_CLK_DN<1>")
	)
	(segment
		(start 315.486796 -255.53416)
		(end 314.963302 -255.6383)
		(width 0.18288)
		(layer "In2.Cu")
		(net "M_B_CPU0_CLK_DN<1>")
	)
	(segment
		(start 315.630052 -255.629918)
		(end 315.486796 -255.53416)
		(width 0.18288)
		(layer "In2.Cu")
		(net "M_B_CPU0_CLK_DN<1>")
	)
	(segment
		(start 313.58459 -256.02692)
		(end 313.58078 -256.032254)
		(width 0.18288)
		(layer "In2.Cu")
		(net "M_B_CPU0_CLK_DN<1>")
	)
	(segment
		(start 341.41664 -250.492006)
		(end 340.92388 -250.695968)
		(width 0.18288)
		(layer "In2.Cu")
		(net "M_B_CPU0_CLK_DN<1>")
	)
	(segment
		(start 300.448218 -257.641852)
		(end 299.762672 -257.875278)
		(width 0.18288)
		(layer "In2.Cu")
		(net "M_B_CPU0_CLK_DN<1>")
	)
	(segment
		(start 303.059084 -257.08102)
		(end 302.91405 -256.987548)
		(width 0.18288)
		(layer "In2.Cu")
		(net "M_B_CPU0_CLK_DN<1>")
	)
	(segment
		(start 302.298862 -257.244596)
		(end 301.7774 -257.356356)
		(width 0.18288)
		(layer "In2.Cu")
		(net "M_B_CPU0_CLK_DN<1>")
	)
	(segment
		(start 313.577224 -256.038096)
		(end 312.63971 -256.224786)
		(width 0.18288)
		(layer "In2.Cu")
		(net "M_B_CPU0_CLK_DN<1>")
	)
	(segment
		(start 341.25408 -249.620024)
		(end 341.25916 -249.620024)
		(width 0.18288)
		(layer "In2.Cu")
		(net "M_B_CPU0_CLK_DN<1>")
	)
	(segment
		(start 299.30217 -259.366766)
		(end 299.029882 -259.366766)
		(width 0.18288)
		(layer "In2.Cu")
		(net "M_B_CPU0_CLK_DN<1>")
	)
	(segment
		(start 340.205568 -250.993656)
		(end 339.565742 -251.258832)
		(width 0.18288)
		(layer "In2.Cu")
		(net "M_B_CPU0_CLK_DN<1>")
	)
	(segment
		(start 314.344558 -255.885696)
		(end 314.201048 -255.789938)
		(width 0.18288)
		(layer "In2.Cu")
		(net "M_B_CPU0_CLK_DN<1>")
	)
	(segment
		(start 304.955702 -256.549144)
		(end 304.86223 -256.694178)
		(width 0.18288)
		(layer "In2.Cu")
		(net "M_B_CPU0_CLK_DN<1>")
	)
	(segment
		(start 341.25916 -249.620024)
		(end 341.57158 -249.932444)
		(width 0.18288)
		(layer "In2.Cu")
		(net "M_B_CPU0_CLK_DN<1>")
	)
	(segment
		(start 340.271608 -250.834144)
		(end 340.205568 -250.993656)
		(width 0.18288)
		(layer "In2.Cu")
		(net "M_B_CPU0_CLK_DN<1>")
	)
	(segment
		(start 334.9371 -251.258832)
		(end 334.240632 -251.547122)
		(width 0.18288)
		(layer "In2.Cu")
		(net "M_B_CPU0_CLK_DN<1>")
	)
	(segment
		(start 299.47362 -258.278376)
		(end 299.47362 -259.104384)
		(width 0.18288)
		(layer "In2.Cu")
		(net "M_B_CPU0_CLK_DN<1>")
	)
	(segment
		(start 313.589924 -256.02565)
		(end 313.58459 -256.02692)
		(width 0.18288)
		(layer "In2.Cu")
		(net "M_B_CPU0_CLK_DN<1>")
	)
	(segment
		(start 304.340768 -256.805938)
		(end 304.195988 -256.712212)
		(width 0.18288)
		(layer "In2.Cu")
		(net "M_B_CPU0_CLK_DN<1>")
	)
	(segment
		(start 319.319656 -254.896366)
		(end 318.936116 -254.972566)
		(width 0.18288)
		(layer "In2.Cu")
		(net "M_B_CPU0_CLK_DN<1>")
	)
	(segment
		(start 302.91405 -256.987548)
		(end 302.392334 -257.099562)
		(width 0.18288)
		(layer "In2.Cu")
		(net "M_B_CPU0_CLK_DN<1>")
	)
	(segment
		(start 341.57158 -249.932444)
		(end 341.57158 -250.337066)
		(width 0.18288)
		(layer "In2.Cu")
		(net "M_B_CPU0_CLK_DN<1>")
	)
	(segment
		(start 299.409612 -259.259324)
		(end 299.30217 -259.366766)
		(width 0.18288)
		(layer "In2.Cu")
		(net "M_B_CPU0_CLK_DN<1>")
	)
	(segment
		(start 314.867544 -255.78181)
		(end 314.344558 -255.885696)
		(width 0.18288)
		(layer "In2.Cu")
		(net "M_B_CPU0_CLK_DN<1>")
	)
	(segment
		(start 340.764622 -250.630182)
		(end 340.271608 -250.834144)
		(width 0.18288)
		(layer "In2.Cu")
		(net "M_B_CPU0_CLK_DN<1>")
	)
	(segment
		(start 341.57158 -250.337066)
		(end 341.41664 -250.492006)
		(width 0.18288)
		(layer "In2.Cu")
		(net "M_B_CPU0_CLK_DN<1>")
	)
	(segment
		(start 316.153038 -255.526032)
		(end 315.630052 -255.629918)
		(width 0.18288)
		(layer "In2.Cu")
		(net "M_B_CPU0_CLK_DN<1>")
	)
	(segment
		(start 303.674018 -256.824226)
		(end 303.580546 -256.96926)
		(width 0.18288)
		(layer "In2.Cu")
		(net "M_B_CPU0_CLK_DN<1>")
	)
	(segment
		(start 314.963302 -255.6383)
		(end 314.867544 -255.78181)
		(width 0.18288)
		(layer "In2.Cu")
		(net "M_B_CPU0_CLK_DN<1>")
	)
	(segment
		(start 339.374734 -250.155964)
		(end 339.37448 -250.15571)
		(width 0.20066)
		(layer "F.Cu")
		(net "M_B_CPU0_CLK_DN<0>")
	)
	(segment
		(start 291.460682 -259.366766)
		(end 290.355782 -259.366766)
		(width 0.20066)
		(layer "F.Cu")
		(net "M_B_CPU0_CLK_DN<0>")
	)
	(segment
		(start 339.37448 -250.15571)
		(end 339.37448 -249.620024)
		(width 0.20066)
		(layer "F.Cu")
		(net "M_B_CPU0_CLK_DN<0>")
	)
	(segment
		(start 294.538908 -257.302762)
		(end 294.005508 -257.302762)
		(width 0.18288)
		(layer "In2.Cu")
		(net "M_B_CPU0_CLK_DN<0>")
	)
	(segment
		(start 333.940404 -250.867164)
		(end 330.253086 -250.867164)
		(width 0.18288)
		(layer "In2.Cu")
		(net "M_B_CPU0_CLK_DN<0>")
	)
	(segment
		(start 317.058294 -254.230632)
		(end 311.359296 -255.386586)
		(width 0.18288)
		(layer "In2.Cu")
		(net "M_B_CPU0_CLK_DN<0>")
	)
	(segment
		(start 294.005508 -257.302762)
		(end 293.883588 -257.180842)
		(width 0.18288)
		(layer "In2.Cu")
		(net "M_B_CPU0_CLK_DN<0>")
	)
	(segment
		(start 292.215316 -259.456936)
		(end 292.016434 -259.655818)
		(width 0.18288)
		(layer "In2.Cu")
		(net "M_B_CPU0_CLK_DN<0>")
	)
	(segment
		(start 291.749734 -259.655818)
		(end 291.460682 -259.366766)
		(width 0.18288)
		(layer "In2.Cu")
		(net "M_B_CPU0_CLK_DN<0>")
	)
	(segment
		(start 299.839888 -256.685034)
		(end 299.69587 -256.590038)
		(width 0.18288)
		(layer "In2.Cu")
		(net "M_B_CPU0_CLK_DN<0>")
	)
	(segment
		(start 291.944044 -258.8387)
		(end 292.215316 -259.109972)
		(width 0.18288)
		(layer "In2.Cu")
		(net "M_B_CPU0_CLK_DN<0>")
	)
	(segment
		(start 306.155852 -255.386586)
		(end 301.250096 -256.394966)
		(width 0.18288)
		(layer "In2.Cu")
		(net "M_B_CPU0_CLK_DN<0>")
	)
	(segment
		(start 339.67801 -249.946414)
		(end 339.67801 -250.178062)
		(width 0.18288)
		(layer "In2.Cu")
		(net "M_B_CPU0_CLK_DN<0>")
	)
	(segment
		(start 293.228268 -257.302762)
		(end 292.694868 -257.302762)
		(width 0.18288)
		(layer "In2.Cu")
		(net "M_B_CPU0_CLK_DN<0>")
	)
	(segment
		(start 339.57387 -250.281948)
		(end 339.349842 -250.374912)
		(width 0.18288)
		(layer "In2.Cu")
		(net "M_B_CPU0_CLK_DN<0>")
	)
	(segment
		(start 292.694868 -257.302762)
		(end 291.944044 -258.053586)
		(width 0.18288)
		(layer "In2.Cu")
		(net "M_B_CPU0_CLK_DN<0>")
	)
	(segment
		(start 335.12887 -250.374912)
		(end 333.940404 -250.867164)
		(width 0.18288)
		(layer "In2.Cu")
		(net "M_B_CPU0_CLK_DN<0>")
	)
	(segment
		(start 330.253086 -250.867164)
		(end 326.889618 -254.230632)
		(width 0.18288)
		(layer "In2.Cu")
		(net "M_B_CPU0_CLK_DN<0>")
	)
	(segment
		(start 298.219368 -257.018282)
		(end 298.07535 -256.92354)
		(width 0.18288)
		(layer "In2.Cu")
		(net "M_B_CPU0_CLK_DN<0>")
	)
	(segment
		(start 299.69587 -256.590038)
		(end 299.173138 -256.69748)
		(width 0.18288)
		(layer "In2.Cu")
		(net "M_B_CPU0_CLK_DN<0>")
	)
	(segment
		(start 297.457876 -257.175)
		(end 296.836338 -257.302762)
		(width 0.18288)
		(layer "In2.Cu")
		(net "M_B_CPU0_CLK_DN<0>")
	)
	(segment
		(start 293.883588 -257.180842)
		(end 293.350188 -257.180842)
		(width 0.18288)
		(layer "In2.Cu")
		(net "M_B_CPU0_CLK_DN<0>")
	)
	(segment
		(start 292.215316 -259.109972)
		(end 292.215316 -259.456936)
		(width 0.18288)
		(layer "In2.Cu")
		(net "M_B_CPU0_CLK_DN<0>")
	)
	(segment
		(start 339.37448 -249.620024)
		(end 339.37448 -249.642884)
		(width 0.18288)
		(layer "In2.Cu")
		(net "M_B_CPU0_CLK_DN<0>")
	)
	(segment
		(start 339.37448 -249.642884)
		(end 339.67801 -249.946414)
		(width 0.18288)
		(layer "In2.Cu")
		(net "M_B_CPU0_CLK_DN<0>")
	)
	(segment
		(start 311.359296 -255.386586)
		(end 306.155852 -255.386586)
		(width 0.18288)
		(layer "In2.Cu")
		(net "M_B_CPU0_CLK_DN<0>")
	)
	(segment
		(start 292.016434 -259.655818)
		(end 291.749734 -259.655818)
		(width 0.18288)
		(layer "In2.Cu")
		(net "M_B_CPU0_CLK_DN<0>")
	)
	(segment
		(start 339.349842 -250.374912)
		(end 335.12887 -250.374912)
		(width 0.18288)
		(layer "In2.Cu")
		(net "M_B_CPU0_CLK_DN<0>")
	)
	(segment
		(start 300.583346 -256.407666)
		(end 300.488604 -256.551684)
		(width 0.18288)
		(layer "In2.Cu")
		(net "M_B_CPU0_CLK_DN<0>")
	)
	(segment
		(start 301.106078 -256.300224)
		(end 300.583346 -256.407666)
		(width 0.18288)
		(layer "In2.Cu")
		(net "M_B_CPU0_CLK_DN<0>")
	)
	(segment
		(start 295.194228 -257.180842)
		(end 294.660828 -257.180842)
		(width 0.18288)
		(layer "In2.Cu")
		(net "M_B_CPU0_CLK_DN<0>")
	)
	(segment
		(start 296.836338 -257.302762)
		(end 295.316148 -257.302762)
		(width 0.18288)
		(layer "In2.Cu")
		(net "M_B_CPU0_CLK_DN<0>")
	)
	(segment
		(start 297.552618 -257.030728)
		(end 297.457876 -257.175)
		(width 0.18288)
		(layer "In2.Cu")
		(net "M_B_CPU0_CLK_DN<0>")
	)
	(segment
		(start 301.250096 -256.394966)
		(end 301.106078 -256.300224)
		(width 0.18288)
		(layer "In2.Cu")
		(net "M_B_CPU0_CLK_DN<0>")
	)
	(segment
		(start 293.350188 -257.180842)
		(end 293.228268 -257.302762)
		(width 0.18288)
		(layer "In2.Cu")
		(net "M_B_CPU0_CLK_DN<0>")
	)
	(segment
		(start 291.944044 -258.053586)
		(end 291.944044 -258.8387)
		(width 0.18288)
		(layer "In2.Cu")
		(net "M_B_CPU0_CLK_DN<0>")
	)
	(segment
		(start 295.316148 -257.302762)
		(end 295.194228 -257.180842)
		(width 0.18288)
		(layer "In2.Cu")
		(net "M_B_CPU0_CLK_DN<0>")
	)
	(segment
		(start 299.173138 -256.69748)
		(end 299.078396 -256.841752)
		(width 0.18288)
		(layer "In2.Cu")
		(net "M_B_CPU0_CLK_DN<0>")
	)
	(segment
		(start 298.07535 -256.92354)
		(end 297.552618 -257.030728)
		(width 0.18288)
		(layer "In2.Cu")
		(net "M_B_CPU0_CLK_DN<0>")
	)
	(segment
		(start 299.078396 -256.841752)
		(end 298.219368 -257.018282)
		(width 0.18288)
		(layer "In2.Cu")
		(net "M_B_CPU0_CLK_DN<0>")
	)
	(segment
		(start 326.889618 -254.230632)
		(end 317.058294 -254.230632)
		(width 0.18288)
		(layer "In2.Cu")
		(net "M_B_CPU0_CLK_DN<0>")
	)
	(segment
		(start 339.67801 -250.178062)
		(end 339.57387 -250.281948)
		(width 0.18288)
		(layer "In2.Cu")
		(net "M_B_CPU0_CLK_DN<0>")
	)
	(segment
		(start 294.660828 -257.180842)
		(end 294.538908 -257.302762)
		(width 0.18288)
		(layer "In2.Cu")
		(net "M_B_CPU0_CLK_DN<0>")
	)
	(segment
		(start 300.488604 -256.551684)
		(end 299.839888 -256.685034)
		(width 0.18288)
		(layer "In2.Cu")
		(net "M_B_CPU0_CLK_DN<0>")
	)
	(segment
		(start 350.292416 -255.011936)
		(end 350.292416 -255.547622)
		(width 0.20066)
		(layer "F.Cu")
		(net "M_B_CPU0_ALERT_N")
	)
	(segment
		(start 350.292162 -255.011682)
		(end 350.292416 -255.011936)
		(width 0.20066)
		(layer "F.Cu")
		(net "M_B_CPU0_ALERT_N")
	)
	(segment
		(start 288.46018 -269.304262)
		(end 288.46018 -269.62354)
		(width 0.20066)
		(layer "F.Cu")
		(net "M_B_CPU0_ALERT_N")
	)
	(segment
		(start 291.225986 -269.141702)
		(end 289.240468 -269.141702)
		(width 0.1016)
		(layer "F.Cu")
		(net "M_B_CPU0_ALERT_N")
	)
	(segment
		(start 289.240468 -269.141702)
		(end 289.09772 -269.141702)
		(width 0.101854)
		(layer "F.Cu")
		(net "M_B_CPU0_ALERT_N")
	)
	(segment
		(start 287.589976 -269.566644)
		(end 286.255714 -269.566644)
		(width 0.20066)
		(layer "F.Cu")
		(net "M_B_CPU0_ALERT_N")
	)
	(segment
		(start 293.799514 -269.566644)
		(end 292.160198 -269.566644)
		(width 0.20066)
		(layer "F.Cu")
		(net "M_B_CPU0_ALERT_N")
	)
	(segment
		(start 289.09772 -269.141702)
		(end 288.62274 -269.141702)
		(width 0.20066)
		(layer "F.Cu")
		(net "M_B_CPU0_ALERT_N")
	)
	(segment
		(start 288.46018 -269.62354)
		(end 288.305748 -269.777972)
		(width 0.20066)
		(layer "F.Cu")
		(net "M_B_CPU0_ALERT_N")
	)
	(segment
		(start 288.305748 -269.777972)
		(end 287.801304 -269.777972)
		(width 0.20066)
		(layer "F.Cu")
		(net "M_B_CPU0_ALERT_N")
	)
	(segment
		(start 292.160198 -269.566644)
		(end 291.735256 -269.141702)
		(width 0.20066)
		(layer "F.Cu")
		(net "M_B_CPU0_ALERT_N")
	)
	(segment
		(start 288.62274 -269.141702)
		(end 288.46018 -269.304262)
		(width 0.20066)
		(layer "F.Cu")
		(net "M_B_CPU0_ALERT_N")
	)
	(segment
		(start 287.801304 -269.777972)
		(end 287.589976 -269.566644)
		(width 0.20066)
		(layer "F.Cu")
		(net "M_B_CPU0_ALERT_N")
	)
	(segment
		(start 291.735256 -269.141702)
		(end 291.630608 -269.141702)
		(width 0.20066)
		(layer "F.Cu")
		(net "M_B_CPU0_ALERT_N")
	)
	(segment
		(start 294.904414 -269.566644)
		(end 293.799514 -269.566644)
		(width 0.20066)
		(layer "F.Cu")
		(net "M_B_CPU0_ALERT_N")
	)
	(segment
		(start 291.630608 -269.141702)
		(end 291.225986 -269.141702)
		(width 0.101854)
		(layer "F.Cu")
		(net "M_B_CPU0_ALERT_N")
	)
	(via
		(at 341.364062 -254.733552)
		(size 0.4318)
		(drill 0.2032)
		(layers "F.Cu" "B.Cu")
		(net "M_B_CPU0_ALERT_N")
	)
	(via
		(at 294.904414 -269.566644)
		(size 0.4572)
		(drill 0.2032)
		(layers "F.Cu" "B.Cu")
		(net "M_B_CPU0_ALERT_N")
	)
	(via
		(at 350.292416 -255.547622)
		(size 0.4572)
		(drill 0.2032)
		(layers "F.Cu" "B.Cu")
		(net "M_B_CPU0_ALERT_N")
	)
	(segment
		(start 349.117412 -255.14046)
		(end 349.09125 -255.155446)
		(width 0.20066)
		(layer "B.Cu")
		(net "M_B_CPU0_ALERT_N")
	)
	(segment
		(start 346.615512 -255.07569)
		(end 346.478606 -255.07569)
		(width 0.20066)
		(layer "B.Cu")
		(net "M_B_CPU0_ALERT_N")
	)
	(segment
		(start 347.237812 -255.14046)
		(end 347.22816 -255.146048)
		(width 0.20066)
		(layer "B.Cu")
		(net "M_B_CPU0_ALERT_N")
	)
	(segment
		(start 342.052656 -255.140714)
		(end 341.36711 -254.744728)
		(width 0.20066)
		(layer "B.Cu")
		(net "M_B_CPU0_ALERT_N")
	)
	(segment
		(start 343.018364 -255.146302)
		(end 342.98255 -255.125728)
		(width 0.20066)
		(layer "B.Cu")
		(net "M_B_CPU0_ALERT_N")
	)
	(segment
		(start 344.897964 -255.146302)
		(end 344.888312 -255.140714)
		(width 0.20066)
		(layer "B.Cu")
		(net "M_B_CPU0_ALERT_N")
	)
	(segment
		(start 345.841828 -255.148588)
		(end 345.828366 -255.140714)
		(width 0.20066)
		(layer "B.Cu")
		(net "M_B_CPU0_ALERT_N")
	)
	(segment
		(start 348.673928 -255.155446)
		(end 348.638114 -255.134872)
		(width 0.20066)
		(layer "B.Cu")
		(net "M_B_CPU0_ALERT_N")
	)
	(segment
		(start 350.289368 -255.536446)
		(end 349.603822 -255.14046)
		(width 0.20066)
		(layer "B.Cu")
		(net "M_B_CPU0_ALERT_N")
	)
	(segment
		(start 346.768166 -255.14046)
		(end 346.758514 -255.134872)
		(width 0.20066)
		(layer "B.Cu")
		(net "M_B_CPU0_ALERT_N")
	)
	(segment
		(start 341.36711 -254.744728)
		(end 341.364062 -254.733552)
		(width 0.20066)
		(layer "B.Cu")
		(net "M_B_CPU0_ALERT_N")
	)
	(segment
		(start 342.565228 -255.125728)
		(end 342.539066 -255.140714)
		(width 0.20066)
		(layer "B.Cu")
		(net "M_B_CPU0_ALERT_N")
	)
	(segment
		(start 346.352114 -255.109472)
		(end 346.298266 -255.140714)
		(width 0.20066)
		(layer "B.Cu")
		(net "M_B_CPU0_ALERT_N")
	)
	(segment
		(start 350.292416 -255.547622)
		(end 350.289368 -255.536446)
		(width 0.20066)
		(layer "B.Cu")
		(net "M_B_CPU0_ALERT_N")
	)
	(segment
		(start 344.428318 -255.135126)
		(end 344.418666 -255.140714)
		(width 0.20066)
		(layer "B.Cu")
		(net "M_B_CPU0_ALERT_N")
	)
	(arc
		(start 344.888312 -255.140714)
		(mid 344.659049 -255.077789)
		(end 344.428318 -255.135126)
		(width 0.20066)
		(layer "B.Cu")
		(net "M_B_CPU0_ALERT_N")
	)
	(arc
		(start 344.418666 -255.140714)
		(mid 344.183716 -255.20364)
		(end 343.948766 -255.140714)
		(width 0.20066)
		(layer "B.Cu")
		(net "M_B_CPU0_ALERT_N")
	)
	(arc
		(start 343.478866 -255.140714)
		(mid 343.249349 -255.203732)
		(end 343.018364 -255.146302)
		(width 0.20066)
		(layer "B.Cu")
		(net "M_B_CPU0_ALERT_N")
	)
	(arc
		(start 342.539066 -255.140714)
		(mid 342.295878 -255.205798)
		(end 342.052656 -255.140714)
		(width 0.20066)
		(layer "B.Cu")
		(net "M_B_CPU0_ALERT_N")
	)
	(arc
		(start 346.478606 -255.07569)
		(mid 346.413135 -255.084249)
		(end 346.352114 -255.109472)
		(width 0.20066)
		(layer "B.Cu")
		(net "M_B_CPU0_ALERT_N")
	)
	(arc
		(start 348.177612 -255.14046)
		(mid 347.942662 -255.20342)
		(end 347.707712 -255.14046)
		(width 0.20066)
		(layer "B.Cu")
		(net "M_B_CPU0_ALERT_N")
	)
	(arc
		(start 345.358466 -255.140714)
		(mid 345.128949 -255.203732)
		(end 344.897964 -255.146302)
		(width 0.20066)
		(layer "B.Cu")
		(net "M_B_CPU0_ALERT_N")
	)
	(arc
		(start 342.98255 -255.125728)
		(mid 342.773906 -255.069749)
		(end 342.565228 -255.125728)
		(width 0.20066)
		(layer "B.Cu")
		(net "M_B_CPU0_ALERT_N")
	)
	(arc
		(start 346.298266 -255.140714)
		(mid 346.071079 -255.203698)
		(end 345.841828 -255.148588)
		(width 0.20066)
		(layer "B.Cu")
		(net "M_B_CPU0_ALERT_N")
	)
	(arc
		(start 349.09125 -255.155446)
		(mid 348.882606 -255.211425)
		(end 348.673928 -255.155446)
		(width 0.20066)
		(layer "B.Cu")
		(net "M_B_CPU0_ALERT_N")
	)
	(arc
		(start 347.707712 -255.14046)
		(mid 347.472762 -255.077534)
		(end 347.237812 -255.14046)
		(width 0.20066)
		(layer "B.Cu")
		(net "M_B_CPU0_ALERT_N")
	)
	(arc
		(start 346.758514 -255.134872)
		(mid 346.692904 -255.091033)
		(end 346.615512 -255.07569)
		(width 0.20066)
		(layer "B.Cu")
		(net "M_B_CPU0_ALERT_N")
	)
	(arc
		(start 343.948766 -255.140714)
		(mid 343.713816 -255.077754)
		(end 343.478866 -255.140714)
		(width 0.20066)
		(layer "B.Cu")
		(net "M_B_CPU0_ALERT_N")
	)
	(arc
		(start 347.22816 -255.146048)
		(mid 346.997429 -255.203409)
		(end 346.768166 -255.14046)
		(width 0.20066)
		(layer "B.Cu")
		(net "M_B_CPU0_ALERT_N")
	)
	(arc
		(start 349.603822 -255.14046)
		(mid 349.360634 -255.075376)
		(end 349.117412 -255.14046)
		(width 0.20066)
		(layer "B.Cu")
		(net "M_B_CPU0_ALERT_N")
	)
	(arc
		(start 345.828366 -255.140714)
		(mid 345.593416 -255.077754)
		(end 345.358466 -255.140714)
		(width 0.20066)
		(layer "B.Cu")
		(net "M_B_CPU0_ALERT_N")
	)
	(arc
		(start 348.638114 -255.134872)
		(mid 348.407129 -255.077421)
		(end 348.177612 -255.14046)
		(width 0.20066)
		(layer "B.Cu")
		(net "M_B_CPU0_ALERT_N")
	)
	(segment
		(start 339.579966 -255.538986)
		(end 339.579966 -255.547622)
		(width 0.088646)
		(layer "In2.Cu")
		(net "M_B_CPU0_ALERT_N")
	)
	(segment
		(start 338.639912 -257.175254)
		(end 338.639912 -257.190748)
		(width 0.088646)
		(layer "In2.Cu")
		(net "M_B_CPU0_ALERT_N")
	)
	(segment
		(start 309.745126 -267.457428)
		(end 309.529988 -267.24229)
		(width 0.18288)
		(layer "In2.Cu")
		(net "M_B_CPU0_ALERT_N")
	)
	(segment
		(start 337.792314 -257.664712)
		(end 337.79206 -257.664712)
		(width 0.088646)
		(layer "In2.Cu")
		(net "M_B_CPU0_ALERT_N")
	)
	(segment
		(start 332.435962 -257.740404)
		(end 332.109572 -257.740404)
		(width 0.088646)
		(layer "In2.Cu")
		(net "M_B_CPU0_ALERT_N")
	)
	(segment
		(start 313.646312 -266.40917)
		(end 312.295032 -266.40917)
		(width 0.18288)
		(layer "In2.Cu")
		(net "M_B_CPU0_ALERT_N")
	)
	(segment
		(start 314.693046 -265.919712)
		(end 314.693046 -266.177776)
		(width 0.18288)
		(layer "In2.Cu")
		(net "M_B_CPU0_ALERT_N")
	)
	(segment
		(start 313.862466 -266.625324)
		(end 313.646312 -266.40917)
		(width 0.18288)
		(layer "In2.Cu")
		(net "M_B_CPU0_ALERT_N")
	)
	(segment
		(start 332.109572 -257.740404)
		(end 331.912722 -257.543554)
		(width 0.088646)
		(layer "In2.Cu")
		(net "M_B_CPU0_ALERT_N")
	)
	(segment
		(start 314.245498 -266.625324)
		(end 313.862466 -266.625324)
		(width 0.18288)
		(layer "In2.Cu")
		(net "M_B_CPU0_ALERT_N")
	)
	(segment
		(start 323.426582 -260.724142)
		(end 317.38697 -263.225788)
		(width 0.18288)
		(layer "In2.Cu")
		(net "M_B_CPU0_ALERT_N")
	)
	(segment
		(start 329.158854 -259.696966)
		(end 324.453758 -259.696966)
		(width 0.18288)
		(layer "In2.Cu")
		(net "M_B_CPU0_ALERT_N")
	)
	(segment
		(start 299.984414 -269.932912)
		(end 299.136054 -269.084552)
		(width 0.18288)
		(layer "In2.Cu")
		(net "M_B_CPU0_ALERT_N")
	)
	(segment
		(start 304.243232 -268.30909)
		(end 302.61941 -269.932912)
		(width 0.18288)
		(layer "In2.Cu")
		(net "M_B_CPU0_ALERT_N")
	)
	(segment
		(start 314.693046 -266.177776)
		(end 314.245498 -266.625324)
		(width 0.18288)
		(layer "In2.Cu")
		(net "M_B_CPU0_ALERT_N")
	)
	(segment
		(start 338.827364 -256.850896)
		(end 338.818474 -256.855976)
		(width 0.088646)
		(layer "In2.Cu")
		(net "M_B_CPU0_ALERT_N")
	)
	(segment
		(start 302.61941 -269.932912)
		(end 299.984414 -269.932912)
		(width 0.18288)
		(layer "In2.Cu")
		(net "M_B_CPU0_ALERT_N")
	)
	(segment
		(start 310.196738 -267.457428)
		(end 309.745126 -267.457428)
		(width 0.18288)
		(layer "In2.Cu")
		(net "M_B_CPU0_ALERT_N")
	)
	(segment
		(start 317.38697 -263.225788)
		(end 314.693046 -265.919712)
		(width 0.18288)
		(layer "In2.Cu")
		(net "M_B_CPU0_ALERT_N")
	)
	(segment
		(start 299.136054 -269.084552)
		(end 295.386506 -269.084552)
		(width 0.18288)
		(layer "In2.Cu")
		(net "M_B_CPU0_ALERT_N")
	)
	(segment
		(start 295.386506 -269.084552)
		(end 294.904414 -269.566644)
		(width 0.18288)
		(layer "In2.Cu")
		(net "M_B_CPU0_ALERT_N")
	)
	(segment
		(start 339.297264 -256.03708)
		(end 339.288374 -256.04216)
		(width 0.088646)
		(layer "In2.Cu")
		(net "M_B_CPU0_ALERT_N")
	)
	(segment
		(start 339.30336 -256.033524)
		(end 339.297264 -256.03708)
		(width 0.088646)
		(layer "In2.Cu")
		(net "M_B_CPU0_ALERT_N")
	)
	(segment
		(start 331.912722 -257.543554)
		(end 331.563218 -257.543554)
		(width 0.088646)
		(layer "In2.Cu")
		(net "M_B_CPU0_ALERT_N")
	)
	(segment
		(start 308.268624 -267.24229)
		(end 308.053486 -267.457428)
		(width 0.18288)
		(layer "In2.Cu")
		(net "M_B_CPU0_ALERT_N")
	)
	(segment
		(start 311.028842 -266.625324)
		(end 310.196738 -267.457428)
		(width 0.18288)
		(layer "In2.Cu")
		(net "M_B_CPU0_ALERT_N")
	)
	(segment
		(start 306.729892 -268.30909)
		(end 304.243232 -268.30909)
		(width 0.18288)
		(layer "In2.Cu")
		(net "M_B_CPU0_ALERT_N")
	)
	(segment
		(start 324.453758 -259.696966)
		(end 323.426582 -260.724142)
		(width 0.18288)
		(layer "In2.Cu")
		(net "M_B_CPU0_ALERT_N")
	)
	(segment
		(start 312.078878 -266.625324)
		(end 311.028842 -266.625324)
		(width 0.18288)
		(layer "In2.Cu")
		(net "M_B_CPU0_ALERT_N")
	)
	(segment
		(start 309.529988 -267.24229)
		(end 308.268624 -267.24229)
		(width 0.18288)
		(layer "In2.Cu")
		(net "M_B_CPU0_ALERT_N")
	)
	(segment
		(start 340.860634 -254.942086)
		(end 340.64575 -255.156716)
		(width 0.088646)
		(layer "In2.Cu")
		(net "M_B_CPU0_ALERT_N")
	)
	(segment
		(start 331.312266 -257.543554)
		(end 329.158854 -259.696966)
		(width 0.18288)
		(layer "In2.Cu")
		(net "M_B_CPU0_ALERT_N")
	)
	(segment
		(start 339.109812 -256.361438)
		(end 339.109812 -256.371344)
		(width 0.088646)
		(layer "In2.Cu")
		(net "M_B_CPU0_ALERT_N")
	)
	(segment
		(start 331.563218 -257.543554)
		(end 331.312266 -257.543554)
		(width 0.18288)
		(layer "In2.Cu")
		(net "M_B_CPU0_ALERT_N")
	)
	(segment
		(start 307.581554 -267.457428)
		(end 306.729892 -268.30909)
		(width 0.18288)
		(layer "In2.Cu")
		(net "M_B_CPU0_ALERT_N")
	)
	(segment
		(start 308.053486 -267.457428)
		(end 307.581554 -267.457428)
		(width 0.18288)
		(layer "In2.Cu")
		(net "M_B_CPU0_ALERT_N")
	)
	(segment
		(start 312.295032 -266.40917)
		(end 312.078878 -266.625324)
		(width 0.18288)
		(layer "In2.Cu")
		(net "M_B_CPU0_ALERT_N")
	)
	(arc
		(start 337.79206 -257.664712)
		(mid 337.604862 -257.614569)
		(end 337.417664 -257.664712)
		(width 0.088646)
		(layer "In2.Cu")
		(net "M_B_CPU0_ALERT_N")
	)
	(arc
		(start 339.288374 -256.04216)
		(mid 339.15746 -256.17852)
		(end 339.109812 -256.361438)
		(width 0.088646)
		(layer "In2.Cu")
		(net "M_B_CPU0_ALERT_N")
	)
	(arc
		(start 336.477864 -257.664712)
		(mid 336.195162 -257.740488)
		(end 335.91246 -257.664712)
		(width 0.088646)
		(layer "In2.Cu")
		(net "M_B_CPU0_ALERT_N")
	)
	(arc
		(start 335.91246 -257.664712)
		(mid 335.725262 -257.614569)
		(end 335.538064 -257.664712)
		(width 0.088646)
		(layer "In2.Cu")
		(net "M_B_CPU0_ALERT_N")
	)
	(arc
		(start 341.364062 -254.733552)
		(mid 341.091606 -254.787747)
		(end 340.860634 -254.942086)
		(width 0.088646)
		(layer "In2.Cu")
		(net "M_B_CPU0_ALERT_N")
	)
	(arc
		(start 334.03286 -257.664712)
		(mid 333.845662 -257.614569)
		(end 333.658464 -257.664712)
		(width 0.088646)
		(layer "In2.Cu")
		(net "M_B_CPU0_ALERT_N")
	)
	(arc
		(start 338.818474 -256.855976)
		(mid 338.68756 -256.992336)
		(end 338.639912 -257.175254)
		(width 0.088646)
		(layer "In2.Cu")
		(net "M_B_CPU0_ALERT_N")
	)
	(arc
		(start 333.09306 -257.664712)
		(mid 332.905862 -257.614569)
		(end 332.718664 -257.664712)
		(width 0.088646)
		(layer "In2.Cu")
		(net "M_B_CPU0_ALERT_N")
	)
	(arc
		(start 339.579966 -255.547622)
		(mid 339.505975 -255.827188)
		(end 339.30336 -256.033524)
		(width 0.088646)
		(layer "In2.Cu")
		(net "M_B_CPU0_ALERT_N")
	)
	(arc
		(start 335.538064 -257.664712)
		(mid 335.255362 -257.740488)
		(end 334.97266 -257.664712)
		(width 0.088646)
		(layer "In2.Cu")
		(net "M_B_CPU0_ALERT_N")
	)
	(arc
		(start 334.598264 -257.664712)
		(mid 334.315562 -257.740488)
		(end 334.03286 -257.664712)
		(width 0.088646)
		(layer "In2.Cu")
		(net "M_B_CPU0_ALERT_N")
	)
	(arc
		(start 334.97266 -257.664712)
		(mid 334.785462 -257.614569)
		(end 334.598264 -257.664712)
		(width 0.088646)
		(layer "In2.Cu")
		(net "M_B_CPU0_ALERT_N")
	)
	(arc
		(start 340.64575 -255.156716)
		(mid 340.404956 -255.275491)
		(end 340.14156 -255.223264)
		(width 0.088646)
		(layer "In2.Cu")
		(net "M_B_CPU0_ALERT_N")
	)
	(arc
		(start 339.109812 -256.371344)
		(mid 339.031701 -256.648293)
		(end 338.827364 -256.850896)
		(width 0.088646)
		(layer "In2.Cu")
		(net "M_B_CPU0_ALERT_N")
	)
	(arc
		(start 339.767164 -255.223264)
		(mid 339.632231 -255.356618)
		(end 339.579966 -255.538986)
		(width 0.088646)
		(layer "In2.Cu")
		(net "M_B_CPU0_ALERT_N")
	)
	(arc
		(start 336.85226 -257.664712)
		(mid 336.665062 -257.614569)
		(end 336.477864 -257.664712)
		(width 0.088646)
		(layer "In2.Cu")
		(net "M_B_CPU0_ALERT_N")
	)
	(arc
		(start 333.658464 -257.664712)
		(mid 333.375762 -257.740488)
		(end 333.09306 -257.664712)
		(width 0.088646)
		(layer "In2.Cu")
		(net "M_B_CPU0_ALERT_N")
	)
	(arc
		(start 337.417664 -257.664712)
		(mid 337.134962 -257.740488)
		(end 336.85226 -257.664712)
		(width 0.088646)
		(layer "In2.Cu")
		(net "M_B_CPU0_ALERT_N")
	)
	(arc
		(start 332.718664 -257.664712)
		(mid 332.582295 -257.721154)
		(end 332.435962 -257.740404)
		(width 0.088646)
		(layer "In2.Cu")
		(net "M_B_CPU0_ALERT_N")
	)
	(arc
		(start 340.14156 -255.223264)
		(mid 339.954362 -255.173121)
		(end 339.767164 -255.223264)
		(width 0.088646)
		(layer "In2.Cu")
		(net "M_B_CPU0_ALERT_N")
	)
	(arc
		(start 338.357718 -257.664712)
		(mid 338.075016 -257.740488)
		(end 337.792314 -257.664712)
		(width 0.088646)
		(layer "In2.Cu")
		(net "M_B_CPU0_ALERT_N")
	)
	(arc
		(start 338.639912 -257.190748)
		(mid 338.560542 -257.464482)
		(end 338.357718 -257.664712)
		(width 0.088646)
		(layer "In2.Cu")
		(net "M_B_CPU0_ALERT_N")
	)
	(segment
		(start 102.242112 -247.714262)
		(end 102.241096 -247.713246)
		(width 0.20066)
		(layer "F.Cu")
		(net "M_A_CPU1_SB_RSP<1>")
	)
	(segment
		(start 102.241096 -247.713246)
		(end 102.241096 -247.179592)
		(width 0.20066)
		(layer "F.Cu")
		(net "M_A_CPU1_SB_RSP<1>")
	)
	(segment
		(start 102.241096 -247.179592)
		(end 102.242366 -247.178322)
		(width 0.20066)
		(layer "F.Cu")
		(net "M_A_CPU1_SB_RSP<1>")
	)
	(segment
		(start 60.947046 -243.216684)
		(end 62.051946 -243.216684)
		(width 0.20066)
		(layer "F.Cu")
		(net "M_A_CPU1_SB_RSP<1>")
	)
	(segment
		(start 89.837514 -247.50268)
		(end 89.8271 -247.496584)
		(width 0.088646)
		(layer "In6.Cu")
		(net "M_A_CPU1_SB_RSP<1>")
	)
	(segment
		(start 84.103972 -247.94464)
		(end 83.520534 -247.94464)
		(width 0.088646)
		(layer "In6.Cu")
		(net "M_A_CPU1_SB_RSP<1>")
	)
	(segment
		(start 98.680524 -247.496584)
		(end 98.678238 -247.497854)
		(width 0.088646)
		(layer "In6.Cu")
		(net "M_A_CPU1_SB_RSP<1>")
	)
	(segment
		(start 80.237584 -246.349012)
		(end 73.810876 -246.349012)
		(width 0.18288)
		(layer "In6.Cu")
		(net "M_A_CPU1_SB_RSP<1>")
	)
	(segment
		(start 98.295714 -247.50268)
		(end 98.2853 -247.496584)
		(width 0.088646)
		(layer "In6.Cu")
		(net "M_A_CPU1_SB_RSP<1>")
	)
	(segment
		(start 91.717114 -247.50268)
		(end 91.7067 -247.496584)
		(width 0.088646)
		(layer "In6.Cu")
		(net "M_A_CPU1_SB_RSP<1>")
	)
	(segment
		(start 69.61378 -247.738646)
		(end 66.404744 -244.52961)
		(width 0.18288)
		(layer "In6.Cu")
		(net "M_A_CPU1_SB_RSP<1>")
	)
	(segment
		(start 101.585014 -246.688864)
		(end 101.5746 -246.682768)
		(width 0.088646)
		(layer "In6.Cu")
		(net "M_A_CPU1_SB_RSP<1>")
	)
	(segment
		(start 73.810876 -246.349012)
		(end 72.421242 -247.738646)
		(width 0.18288)
		(layer "In6.Cu")
		(net "M_A_CPU1_SB_RSP<1>")
	)
	(segment
		(start 72.421242 -247.738646)
		(end 69.61378 -247.738646)
		(width 0.18288)
		(layer "In6.Cu")
		(net "M_A_CPU1_SB_RSP<1>")
	)
	(segment
		(start 98.678238 -247.497854)
		(end 98.67011 -247.50268)
		(width 0.088646)
		(layer "In6.Cu")
		(net "M_A_CPU1_SB_RSP<1>")
	)
	(segment
		(start 102.085902 -247.44934)
		(end 102.00767 -247.470168)
		(width 0.088646)
		(layer "In6.Cu")
		(net "M_A_CPU1_SB_RSP<1>")
	)
	(segment
		(start 94.925896 -247.494044)
		(end 94.911164 -247.50268)
		(width 0.088646)
		(layer "In6.Cu")
		(net "M_A_CPU1_SB_RSP<1>")
	)
	(segment
		(start 66.404744 -244.52961)
		(end 63.364872 -244.52961)
		(width 0.18288)
		(layer "In6.Cu")
		(net "M_A_CPU1_SB_RSP<1>")
	)
	(segment
		(start 88.347296 -247.494044)
		(end 88.332564 -247.50268)
		(width 0.088646)
		(layer "In6.Cu")
		(net "M_A_CPU1_SB_RSP<1>")
	)
	(segment
		(start 100.645468 -246.688864)
		(end 100.635054 -246.682768)
		(width 0.088646)
		(layer "In6.Cu")
		(net "M_A_CPU1_SB_RSP<1>")
	)
	(segment
		(start 93.986096 -247.494044)
		(end 93.971364 -247.50268)
		(width 0.088646)
		(layer "In6.Cu")
		(net "M_A_CPU1_SB_RSP<1>")
	)
	(segment
		(start 63.364872 -244.52961)
		(end 62.051946 -243.216684)
		(width 0.18288)
		(layer "In6.Cu")
		(net "M_A_CPU1_SB_RSP<1>")
	)
	(segment
		(start 96.416114 -247.50268)
		(end 96.4057 -247.496584)
		(width 0.088646)
		(layer "In6.Cu")
		(net "M_A_CPU1_SB_RSP<1>")
	)
	(segment
		(start 99.619054 -247.4976)
		(end 99.610164 -247.50268)
		(width 0.088646)
		(layer "In6.Cu")
		(net "M_A_CPU1_SB_RSP<1>")
	)
	(segment
		(start 81.833212 -247.94464)
		(end 80.237584 -246.349012)
		(width 0.18288)
		(layer "In6.Cu")
		(net "M_A_CPU1_SB_RSP<1>")
	)
	(segment
		(start 101.59111 -246.69242)
		(end 101.585014 -246.688864)
		(width 0.088646)
		(layer "In6.Cu")
		(net "M_A_CPU1_SB_RSP<1>")
	)
	(segment
		(start 84.45627 -247.592342)
		(end 84.103972 -247.94464)
		(width 0.088646)
		(layer "In6.Cu")
		(net "M_A_CPU1_SB_RSP<1>")
	)
	(segment
		(start 90.222324 -247.496584)
		(end 90.21191 -247.50268)
		(width 0.088646)
		(layer "In6.Cu")
		(net "M_A_CPU1_SB_RSP<1>")
	)
	(segment
		(start 92.101924 -247.496584)
		(end 92.09151 -247.50268)
		(width 0.088646)
		(layer "In6.Cu")
		(net "M_A_CPU1_SB_RSP<1>")
	)
	(segment
		(start 96.800924 -247.496584)
		(end 96.79051 -247.50268)
		(width 0.088646)
		(layer "In6.Cu")
		(net "M_A_CPU1_SB_RSP<1>")
	)
	(segment
		(start 93.046296 -247.494044)
		(end 93.031564 -247.50268)
		(width 0.088646)
		(layer "In6.Cu")
		(net "M_A_CPU1_SB_RSP<1>")
	)
	(segment
		(start 83.520534 -247.94464)
		(end 81.833212 -247.94464)
		(width 0.18288)
		(layer "In6.Cu")
		(net "M_A_CPU1_SB_RSP<1>")
	)
	(segment
		(start 102.242366 -247.178322)
		(end 102.085902 -247.44934)
		(width 0.088646)
		(layer "In6.Cu")
		(net "M_A_CPU1_SB_RSP<1>")
	)
	(segment
		(start 99.797616 -247.162828)
		(end 99.797616 -247.178322)
		(width 0.088646)
		(layer "In6.Cu")
		(net "M_A_CPU1_SB_RSP<1>")
	)
	(arc
		(start 99.797616 -247.178322)
		(mid 99.749937 -247.361222)
		(end 99.619054 -247.4976)
		(width 0.088646)
		(layer "In6.Cu")
		(net "M_A_CPU1_SB_RSP<1>")
	)
	(arc
		(start 90.777568 -247.50268)
		(mid 90.500755 -247.42681)
		(end 90.222324 -247.496584)
		(width 0.088646)
		(layer "In6.Cu")
		(net "M_A_CPU1_SB_RSP<1>")
	)
	(arc
		(start 91.151964 -247.50268)
		(mid 90.964766 -247.552823)
		(end 90.777568 -247.50268)
		(width 0.088646)
		(layer "In6.Cu")
		(net "M_A_CPU1_SB_RSP<1>")
	)
	(arc
		(start 94.911164 -247.50268)
		(mid 94.723966 -247.552823)
		(end 94.536768 -247.50268)
		(width 0.088646)
		(layer "In6.Cu")
		(net "M_A_CPU1_SB_RSP<1>")
	)
	(arc
		(start 87.018368 -247.50268)
		(mid 86.735666 -247.426904)
		(end 86.452964 -247.50268)
		(width 0.088646)
		(layer "In6.Cu")
		(net "M_A_CPU1_SB_RSP<1>")
	)
	(arc
		(start 94.536768 -247.50268)
		(mid 94.262569 -247.426845)
		(end 93.986096 -247.494044)
		(width 0.088646)
		(layer "In6.Cu")
		(net "M_A_CPU1_SB_RSP<1>")
	)
	(arc
		(start 96.79051 -247.50268)
		(mid 96.603312 -247.552823)
		(end 96.416114 -247.50268)
		(width 0.088646)
		(layer "In6.Cu")
		(net "M_A_CPU1_SB_RSP<1>")
	)
	(arc
		(start 88.897968 -247.50268)
		(mid 88.623769 -247.426845)
		(end 88.347296 -247.494044)
		(width 0.088646)
		(layer "In6.Cu")
		(net "M_A_CPU1_SB_RSP<1>")
	)
	(arc
		(start 93.031564 -247.50268)
		(mid 92.844366 -247.552823)
		(end 92.657168 -247.50268)
		(width 0.088646)
		(layer "In6.Cu")
		(net "M_A_CPU1_SB_RSP<1>")
	)
	(arc
		(start 85.513164 -247.50268)
		(mid 85.325966 -247.552823)
		(end 85.138768 -247.50268)
		(width 0.088646)
		(layer "In6.Cu")
		(net "M_A_CPU1_SB_RSP<1>")
	)
	(arc
		(start 98.2853 -247.496584)
		(mid 98.007122 -247.426861)
		(end 97.730564 -247.50268)
		(width 0.088646)
		(layer "In6.Cu")
		(net "M_A_CPU1_SB_RSP<1>")
	)
	(arc
		(start 87.392764 -247.50268)
		(mid 87.205566 -247.552823)
		(end 87.018368 -247.50268)
		(width 0.088646)
		(layer "In6.Cu")
		(net "M_A_CPU1_SB_RSP<1>")
	)
	(arc
		(start 97.356168 -247.50268)
		(mid 97.079355 -247.42681)
		(end 96.800924 -247.496584)
		(width 0.088646)
		(layer "In6.Cu")
		(net "M_A_CPU1_SB_RSP<1>")
	)
	(arc
		(start 101.019864 -246.688864)
		(mid 100.832666 -246.739007)
		(end 100.645468 -246.688864)
		(width 0.088646)
		(layer "In6.Cu")
		(net "M_A_CPU1_SB_RSP<1>")
	)
	(arc
		(start 97.730564 -247.50268)
		(mid 97.543366 -247.552823)
		(end 97.356168 -247.50268)
		(width 0.088646)
		(layer "In6.Cu")
		(net "M_A_CPU1_SB_RSP<1>")
	)
	(arc
		(start 93.971364 -247.50268)
		(mid 93.784166 -247.552823)
		(end 93.596968 -247.50268)
		(width 0.088646)
		(layer "In6.Cu")
		(net "M_A_CPU1_SB_RSP<1>")
	)
	(arc
		(start 88.332564 -247.50268)
		(mid 88.145366 -247.552823)
		(end 87.958168 -247.50268)
		(width 0.088646)
		(layer "In6.Cu")
		(net "M_A_CPU1_SB_RSP<1>")
	)
	(arc
		(start 100.635054 -246.682768)
		(mid 100.356622 -246.612922)
		(end 100.07981 -246.688864)
		(width 0.088646)
		(layer "In6.Cu")
		(net "M_A_CPU1_SB_RSP<1>")
	)
	(arc
		(start 91.7067 -247.496584)
		(mid 91.428522 -247.426861)
		(end 91.151964 -247.50268)
		(width 0.088646)
		(layer "In6.Cu")
		(net "M_A_CPU1_SB_RSP<1>")
	)
	(arc
		(start 96.4057 -247.496584)
		(mid 96.127522 -247.426861)
		(end 95.850964 -247.50268)
		(width 0.088646)
		(layer "In6.Cu")
		(net "M_A_CPU1_SB_RSP<1>")
	)
	(arc
		(start 90.21191 -247.50268)
		(mid 90.024712 -247.552823)
		(end 89.837514 -247.50268)
		(width 0.088646)
		(layer "In6.Cu")
		(net "M_A_CPU1_SB_RSP<1>")
	)
	(arc
		(start 102.00767 -247.470168)
		(mid 101.904525 -247.340143)
		(end 101.867716 -247.178322)
		(width 0.088646)
		(layer "In6.Cu")
		(net "M_A_CPU1_SB_RSP<1>")
	)
	(arc
		(start 100.07981 -246.688864)
		(mid 99.876987 -246.889095)
		(end 99.797616 -247.162828)
		(width 0.088646)
		(layer "In6.Cu")
		(net "M_A_CPU1_SB_RSP<1>")
	)
	(arc
		(start 99.235768 -247.50268)
		(mid 98.958955 -247.42681)
		(end 98.680524 -247.496584)
		(width 0.088646)
		(layer "In6.Cu")
		(net "M_A_CPU1_SB_RSP<1>")
	)
	(arc
		(start 89.8271 -247.496584)
		(mid 89.548922 -247.426861)
		(end 89.272364 -247.50268)
		(width 0.088646)
		(layer "In6.Cu")
		(net "M_A_CPU1_SB_RSP<1>")
	)
	(arc
		(start 95.850964 -247.50268)
		(mid 95.663766 -247.552823)
		(end 95.476568 -247.50268)
		(width 0.088646)
		(layer "In6.Cu")
		(net "M_A_CPU1_SB_RSP<1>")
	)
	(arc
		(start 84.573364 -247.50268)
		(mid 84.511886 -247.543682)
		(end 84.45627 -247.592342)
		(width 0.088646)
		(layer "In6.Cu")
		(net "M_A_CPU1_SB_RSP<1>")
	)
	(arc
		(start 101.867716 -247.178322)
		(mid 101.793725 -246.898756)
		(end 101.59111 -246.69242)
		(width 0.088646)
		(layer "In6.Cu")
		(net "M_A_CPU1_SB_RSP<1>")
	)
	(arc
		(start 99.610164 -247.50268)
		(mid 99.422966 -247.552823)
		(end 99.235768 -247.50268)
		(width 0.088646)
		(layer "In6.Cu")
		(net "M_A_CPU1_SB_RSP<1>")
	)
	(arc
		(start 92.657168 -247.50268)
		(mid 92.380355 -247.42681)
		(end 92.101924 -247.496584)
		(width 0.088646)
		(layer "In6.Cu")
		(net "M_A_CPU1_SB_RSP<1>")
	)
	(arc
		(start 89.272364 -247.50268)
		(mid 89.085166 -247.552823)
		(end 88.897968 -247.50268)
		(width 0.088646)
		(layer "In6.Cu")
		(net "M_A_CPU1_SB_RSP<1>")
	)
	(arc
		(start 86.078568 -247.50268)
		(mid 85.795866 -247.426904)
		(end 85.513164 -247.50268)
		(width 0.088646)
		(layer "In6.Cu")
		(net "M_A_CPU1_SB_RSP<1>")
	)
	(arc
		(start 92.09151 -247.50268)
		(mid 91.904312 -247.552823)
		(end 91.717114 -247.50268)
		(width 0.088646)
		(layer "In6.Cu")
		(net "M_A_CPU1_SB_RSP<1>")
	)
	(arc
		(start 95.476568 -247.50268)
		(mid 95.202369 -247.426845)
		(end 94.925896 -247.494044)
		(width 0.088646)
		(layer "In6.Cu")
		(net "M_A_CPU1_SB_RSP<1>")
	)
	(arc
		(start 87.958168 -247.50268)
		(mid 87.675466 -247.426904)
		(end 87.392764 -247.50268)
		(width 0.088646)
		(layer "In6.Cu")
		(net "M_A_CPU1_SB_RSP<1>")
	)
	(arc
		(start 85.138768 -247.50268)
		(mid 84.856066 -247.426904)
		(end 84.573364 -247.50268)
		(width 0.088646)
		(layer "In6.Cu")
		(net "M_A_CPU1_SB_RSP<1>")
	)
	(arc
		(start 101.5746 -246.682768)
		(mid 101.296422 -246.613045)
		(end 101.019864 -246.688864)
		(width 0.088646)
		(layer "In6.Cu")
		(net "M_A_CPU1_SB_RSP<1>")
	)
	(arc
		(start 93.596968 -247.50268)
		(mid 93.322769 -247.426845)
		(end 93.046296 -247.494044)
		(width 0.088646)
		(layer "In6.Cu")
		(net "M_A_CPU1_SB_RSP<1>")
	)
	(arc
		(start 98.67011 -247.50268)
		(mid 98.482912 -247.552823)
		(end 98.295714 -247.50268)
		(width 0.088646)
		(layer "In6.Cu")
		(net "M_A_CPU1_SB_RSP<1>")
	)
	(arc
		(start 86.452964 -247.50268)
		(mid 86.265766 -247.552823)
		(end 86.078568 -247.50268)
		(width 0.088646)
		(layer "In6.Cu")
		(net "M_A_CPU1_SB_RSP<1>")
	)
	(segment
		(start 102.242112 -249.342148)
		(end 102.242366 -249.341894)
		(width 0.20066)
		(layer "F.Cu")
		(net "M_A_CPU1_SB_RSP<0>")
	)
	(segment
		(start 102.242366 -249.341894)
		(end 102.242366 -248.806208)
		(width 0.20066)
		(layer "F.Cu")
		(net "M_A_CPU1_SB_RSP<0>")
	)
	(segment
		(start 53.403246 -243.216684)
		(end 54.508146 -243.216684)
		(width 0.20066)
		(layer "F.Cu")
		(net "M_A_CPU1_SB_RSP<0>")
	)
	(segment
		(start 66.371216 -247.040654)
		(end 61.731144 -247.040654)
		(width 0.18288)
		(layer "In6.Cu")
		(net "M_A_CPU1_SB_RSP<0>")
	)
	(segment
		(start 72.580246 -249.69216)
		(end 69.022722 -249.69216)
		(width 0.18288)
		(layer "In6.Cu")
		(net "M_A_CPU1_SB_RSP<0>")
	)
	(segment
		(start 59.971686 -246.028972)
		(end 59.159648 -245.495826)
		(width 0.18288)
		(layer "In6.Cu")
		(net "M_A_CPU1_SB_RSP<0>")
	)
	(segment
		(start 84.960968 -249.924824)
		(end 83.520534 -249.924824)
		(width 0.088646)
		(layer "In6.Cu")
		(net "M_A_CPU1_SB_RSP<0>")
	)
	(segment
		(start 69.022722 -249.69216)
		(end 66.371216 -247.040654)
		(width 0.18288)
		(layer "In6.Cu")
		(net "M_A_CPU1_SB_RSP<0>")
	)
	(segment
		(start 59.159648 -245.495826)
		(end 58.795412 -245.34495)
		(width 0.18288)
		(layer "In6.Cu")
		(net "M_A_CPU1_SB_RSP<0>")
	)
	(segment
		(start 58.795412 -245.34495)
		(end 56.216042 -245.074948)
		(width 0.18288)
		(layer "In6.Cu")
		(net "M_A_CPU1_SB_RSP<0>")
	)
	(segment
		(start 61.137546 -246.794782)
		(end 59.971686 -246.028972)
		(width 0.18288)
		(layer "In6.Cu")
		(net "M_A_CPU1_SB_RSP<0>")
	)
	(segment
		(start 82.373724 -249.924824)
		(end 79.824326 -247.375426)
		(width 0.18288)
		(layer "In6.Cu")
		(net "M_A_CPU1_SB_RSP<0>")
	)
	(segment
		(start 54.84114 -244.52453)
		(end 54.770782 -244.490748)
		(width 0.18288)
		(layer "In6.Cu")
		(net "M_A_CPU1_SB_RSP<0>")
	)
	(segment
		(start 94.921324 -248.487946)
		(end 94.91091 -248.48185)
		(width 0.088646)
		(layer "In6.Cu")
		(net "M_A_CPU1_SB_RSP<0>")
	)
	(segment
		(start 86.55431 -249.29211)
		(end 86.548214 -249.295666)
		(width 0.088646)
		(layer "In6.Cu")
		(net "M_A_CPU1_SB_RSP<0>")
	)
	(segment
		(start 90.226896 -248.490486)
		(end 90.212164 -248.48185)
		(width 0.088646)
		(layer "In6.Cu")
		(net "M_A_CPU1_SB_RSP<0>")
	)
	(segment
		(start 98.685096 -248.490486)
		(end 98.678238 -248.486422)
		(width 0.088646)
		(layer "In6.Cu")
		(net "M_A_CPU1_SB_RSP<0>")
	)
	(segment
		(start 102.242366 -248.806208)
		(end 101.569266 -248.52757)
		(width 0.088646)
		(layer "In6.Cu")
		(net "M_A_CPU1_SB_RSP<0>")
	)
	(segment
		(start 56.216042 -245.074948)
		(end 55.42153 -244.802914)
		(width 0.18288)
		(layer "In6.Cu")
		(net "M_A_CPU1_SB_RSP<0>")
	)
	(segment
		(start 86.548214 -249.295666)
		(end 86.533482 -249.304302)
		(width 0.088646)
		(layer "In6.Cu")
		(net "M_A_CPU1_SB_RSP<0>")
	)
	(segment
		(start 54.77002 -244.49151)
		(end 54.26964 -244.49151)
		(width 0.18288)
		(layer "In6.Cu")
		(net "M_A_CPU1_SB_RSP<0>")
	)
	(segment
		(start 99.624896 -248.490486)
		(end 99.610164 -248.48185)
		(width 0.088646)
		(layer "In6.Cu")
		(net "M_A_CPU1_SB_RSP<0>")
	)
	(segment
		(start 74.89698 -247.375426)
		(end 72.580246 -249.69216)
		(width 0.18288)
		(layer "In6.Cu")
		(net "M_A_CPU1_SB_RSP<0>")
	)
	(segment
		(start 54.26964 -244.49151)
		(end 54.007766 -244.229636)
		(width 0.18288)
		(layer "In6.Cu")
		(net "M_A_CPU1_SB_RSP<0>")
	)
	(segment
		(start 54.007766 -243.717064)
		(end 54.508146 -243.216684)
		(width 0.18288)
		(layer "In6.Cu")
		(net "M_A_CPU1_SB_RSP<0>")
	)
	(segment
		(start 85.53069 -249.355102)
		(end 84.960968 -249.924824)
		(width 0.088646)
		(layer "In6.Cu")
		(net "M_A_CPU1_SB_RSP<0>")
	)
	(segment
		(start 55.42153 -244.802914)
		(end 54.84114 -244.52453)
		(width 0.18288)
		(layer "In6.Cu")
		(net "M_A_CPU1_SB_RSP<0>")
	)
	(segment
		(start 100.560378 -248.487946)
		(end 100.549964 -248.48185)
		(width 0.088646)
		(layer "In6.Cu")
		(net "M_A_CPU1_SB_RSP<0>")
	)
	(segment
		(start 93.981778 -248.487946)
		(end 93.971364 -248.48185)
		(width 0.088646)
		(layer "In6.Cu")
		(net "M_A_CPU1_SB_RSP<0>")
	)
	(segment
		(start 93.046296 -248.490486)
		(end 93.031564 -248.48185)
		(width 0.088646)
		(layer "In6.Cu")
		(net "M_A_CPU1_SB_RSP<0>")
	)
	(segment
		(start 101.569266 -248.52757)
		(end 101.568758 -248.52757)
		(width 0.088646)
		(layer "In6.Cu")
		(net "M_A_CPU1_SB_RSP<0>")
	)
	(segment
		(start 88.347296 -248.490486)
		(end 88.332564 -248.48185)
		(width 0.088646)
		(layer "In6.Cu")
		(net "M_A_CPU1_SB_RSP<0>")
	)
	(segment
		(start 54.770782 -244.490748)
		(end 54.77002 -244.49151)
		(width 0.18288)
		(layer "In6.Cu")
		(net "M_A_CPU1_SB_RSP<0>")
	)
	(segment
		(start 87.018368 -248.48185)
		(end 87.009478 -248.48693)
		(width 0.088646)
		(layer "In6.Cu")
		(net "M_A_CPU1_SB_RSP<0>")
	)
	(segment
		(start 83.520534 -249.924824)
		(end 82.373724 -249.924824)
		(width 0.18288)
		(layer "In6.Cu")
		(net "M_A_CPU1_SB_RSP<0>")
	)
	(segment
		(start 96.805496 -248.490486)
		(end 96.790764 -248.48185)
		(width 0.088646)
		(layer "In6.Cu")
		(net "M_A_CPU1_SB_RSP<0>")
	)
	(segment
		(start 101.568758 -248.52757)
		(end 101.48951 -248.48185)
		(width 0.088646)
		(layer "In6.Cu")
		(net "M_A_CPU1_SB_RSP<0>")
	)
	(segment
		(start 98.678238 -248.486422)
		(end 98.670364 -248.48185)
		(width 0.088646)
		(layer "In6.Cu")
		(net "M_A_CPU1_SB_RSP<0>")
	)
	(segment
		(start 61.731144 -247.040654)
		(end 61.137546 -246.794782)
		(width 0.18288)
		(layer "In6.Cu")
		(net "M_A_CPU1_SB_RSP<0>")
	)
	(segment
		(start 54.007766 -244.229636)
		(end 54.007766 -243.717064)
		(width 0.18288)
		(layer "In6.Cu")
		(net "M_A_CPU1_SB_RSP<0>")
	)
	(segment
		(start 79.824326 -247.375426)
		(end 74.89698 -247.375426)
		(width 0.18288)
		(layer "In6.Cu")
		(net "M_A_CPU1_SB_RSP<0>")
	)
	(segment
		(start 92.106496 -248.490486)
		(end 92.091764 -248.48185)
		(width 0.088646)
		(layer "In6.Cu")
		(net "M_A_CPU1_SB_RSP<0>")
	)
	(arc
		(start 97.356168 -248.48185)
		(mid 97.081939 -248.557775)
		(end 96.805496 -248.490486)
		(width 0.088646)
		(layer "In6.Cu")
		(net "M_A_CPU1_SB_RSP<0>")
	)
	(arc
		(start 87.392764 -248.48185)
		(mid 87.205566 -248.431707)
		(end 87.018368 -248.48185)
		(width 0.088646)
		(layer "In6.Cu")
		(net "M_A_CPU1_SB_RSP<0>")
	)
	(arc
		(start 88.332564 -248.48185)
		(mid 88.145366 -248.431707)
		(end 87.958168 -248.48185)
		(width 0.088646)
		(layer "In6.Cu")
		(net "M_A_CPU1_SB_RSP<0>")
	)
	(arc
		(start 95.850964 -248.48185)
		(mid 95.663766 -248.431707)
		(end 95.476568 -248.48185)
		(width 0.088646)
		(layer "In6.Cu")
		(net "M_A_CPU1_SB_RSP<0>")
	)
	(arc
		(start 85.608414 -249.295666)
		(mid 85.567605 -249.322838)
		(end 85.53069 -249.355102)
		(width 0.088646)
		(layer "In6.Cu")
		(net "M_A_CPU1_SB_RSP<0>")
	)
	(arc
		(start 94.536514 -248.48185)
		(mid 94.259955 -248.557559)
		(end 93.981778 -248.487946)
		(width 0.088646)
		(layer "In6.Cu")
		(net "M_A_CPU1_SB_RSP<0>")
	)
	(arc
		(start 86.830916 -248.806208)
		(mid 86.756925 -249.085774)
		(end 86.55431 -249.29211)
		(width 0.088646)
		(layer "In6.Cu")
		(net "M_A_CPU1_SB_RSP<0>")
	)
	(arc
		(start 100.549964 -248.48185)
		(mid 100.362766 -248.431707)
		(end 100.175568 -248.48185)
		(width 0.088646)
		(layer "In6.Cu")
		(net "M_A_CPU1_SB_RSP<0>")
	)
	(arc
		(start 89.272364 -248.48185)
		(mid 89.085166 -248.431707)
		(end 88.897968 -248.48185)
		(width 0.088646)
		(layer "In6.Cu")
		(net "M_A_CPU1_SB_RSP<0>")
	)
	(arc
		(start 91.151964 -248.48185)
		(mid 90.964766 -248.431707)
		(end 90.777568 -248.48185)
		(width 0.088646)
		(layer "In6.Cu")
		(net "M_A_CPU1_SB_RSP<0>")
	)
	(arc
		(start 93.596968 -248.48185)
		(mid 93.322739 -248.557775)
		(end 93.046296 -248.490486)
		(width 0.088646)
		(layer "In6.Cu")
		(net "M_A_CPU1_SB_RSP<0>")
	)
	(arc
		(start 90.212164 -248.48185)
		(mid 90.024966 -248.431707)
		(end 89.837768 -248.48185)
		(width 0.088646)
		(layer "In6.Cu")
		(net "M_A_CPU1_SB_RSP<0>")
	)
	(arc
		(start 90.777568 -248.48185)
		(mid 90.503339 -248.557775)
		(end 90.226896 -248.490486)
		(width 0.088646)
		(layer "In6.Cu")
		(net "M_A_CPU1_SB_RSP<0>")
	)
	(arc
		(start 101.48951 -248.48185)
		(mid 101.302312 -248.431707)
		(end 101.115114 -248.48185)
		(width 0.088646)
		(layer "In6.Cu")
		(net "M_A_CPU1_SB_RSP<0>")
	)
	(arc
		(start 98.670364 -248.48185)
		(mid 98.483166 -248.431707)
		(end 98.295968 -248.48185)
		(width 0.088646)
		(layer "In6.Cu")
		(net "M_A_CPU1_SB_RSP<0>")
	)
	(arc
		(start 94.91091 -248.48185)
		(mid 94.723712 -248.431707)
		(end 94.536514 -248.48185)
		(width 0.088646)
		(layer "In6.Cu")
		(net "M_A_CPU1_SB_RSP<0>")
	)
	(arc
		(start 88.897968 -248.48185)
		(mid 88.623739 -248.557775)
		(end 88.347296 -248.490486)
		(width 0.088646)
		(layer "In6.Cu")
		(net "M_A_CPU1_SB_RSP<0>")
	)
	(arc
		(start 99.235768 -248.48185)
		(mid 98.961539 -248.557775)
		(end 98.685096 -248.490486)
		(width 0.088646)
		(layer "In6.Cu")
		(net "M_A_CPU1_SB_RSP<0>")
	)
	(arc
		(start 89.837768 -248.48185)
		(mid 89.555066 -248.557592)
		(end 89.272364 -248.48185)
		(width 0.088646)
		(layer "In6.Cu")
		(net "M_A_CPU1_SB_RSP<0>")
	)
	(arc
		(start 95.476568 -248.48185)
		(mid 95.199755 -248.557686)
		(end 94.921324 -248.487946)
		(width 0.088646)
		(layer "In6.Cu")
		(net "M_A_CPU1_SB_RSP<0>")
	)
	(arc
		(start 87.009478 -248.48693)
		(mid 86.878564 -248.62329)
		(end 86.830916 -248.806208)
		(width 0.088646)
		(layer "In6.Cu")
		(net "M_A_CPU1_SB_RSP<0>")
	)
	(arc
		(start 96.790764 -248.48185)
		(mid 96.603566 -248.431707)
		(end 96.416368 -248.48185)
		(width 0.088646)
		(layer "In6.Cu")
		(net "M_A_CPU1_SB_RSP<0>")
	)
	(arc
		(start 98.295968 -248.48185)
		(mid 98.013266 -248.557592)
		(end 97.730564 -248.48185)
		(width 0.088646)
		(layer "In6.Cu")
		(net "M_A_CPU1_SB_RSP<0>")
	)
	(arc
		(start 97.730564 -248.48185)
		(mid 97.543366 -248.431707)
		(end 97.356168 -248.48185)
		(width 0.088646)
		(layer "In6.Cu")
		(net "M_A_CPU1_SB_RSP<0>")
	)
	(arc
		(start 96.416368 -248.48185)
		(mid 96.133666 -248.557592)
		(end 95.850964 -248.48185)
		(width 0.088646)
		(layer "In6.Cu")
		(net "M_A_CPU1_SB_RSP<0>")
	)
	(arc
		(start 92.091764 -248.48185)
		(mid 91.904566 -248.431707)
		(end 91.717368 -248.48185)
		(width 0.088646)
		(layer "In6.Cu")
		(net "M_A_CPU1_SB_RSP<0>")
	)
	(arc
		(start 91.717368 -248.48185)
		(mid 91.434666 -248.557592)
		(end 91.151964 -248.48185)
		(width 0.088646)
		(layer "In6.Cu")
		(net "M_A_CPU1_SB_RSP<0>")
	)
	(arc
		(start 93.031564 -248.48185)
		(mid 92.844366 -248.431707)
		(end 92.657168 -248.48185)
		(width 0.088646)
		(layer "In6.Cu")
		(net "M_A_CPU1_SB_RSP<0>")
	)
	(arc
		(start 101.115114 -248.48185)
		(mid 100.838555 -248.557559)
		(end 100.560378 -248.487946)
		(width 0.088646)
		(layer "In6.Cu")
		(net "M_A_CPU1_SB_RSP<0>")
	)
	(arc
		(start 85.98281 -249.295666)
		(mid 85.795612 -249.245523)
		(end 85.608414 -249.295666)
		(width 0.088646)
		(layer "In6.Cu")
		(net "M_A_CPU1_SB_RSP<0>")
	)
	(arc
		(start 87.958168 -248.48185)
		(mid 87.675466 -248.557592)
		(end 87.392764 -248.48185)
		(width 0.088646)
		(layer "In6.Cu")
		(net "M_A_CPU1_SB_RSP<0>")
	)
	(arc
		(start 86.533482 -249.304302)
		(mid 86.257007 -249.371622)
		(end 85.98281 -249.295666)
		(width 0.088646)
		(layer "In6.Cu")
		(net "M_A_CPU1_SB_RSP<0>")
	)
	(arc
		(start 93.971364 -248.48185)
		(mid 93.784166 -248.431707)
		(end 93.596968 -248.48185)
		(width 0.088646)
		(layer "In6.Cu")
		(net "M_A_CPU1_SB_RSP<0>")
	)
	(arc
		(start 92.657168 -248.48185)
		(mid 92.382939 -248.557775)
		(end 92.106496 -248.490486)
		(width 0.088646)
		(layer "In6.Cu")
		(net "M_A_CPU1_SB_RSP<0>")
	)
	(arc
		(start 99.610164 -248.48185)
		(mid 99.422966 -248.431707)
		(end 99.235768 -248.48185)
		(width 0.088646)
		(layer "In6.Cu")
		(net "M_A_CPU1_SB_RSP<0>")
	)
	(arc
		(start 100.175568 -248.48185)
		(mid 99.901339 -248.557775)
		(end 99.624896 -248.490486)
		(width 0.088646)
		(layer "In6.Cu")
		(net "M_A_CPU1_SB_RSP<0>")
	)
	(segment
		(start 63.636144 -247.04167)
		(end 64.061086 -246.616728)
		(width 0.20066)
		(layer "F.Cu")
		(net "M_A_CPU1_SB_PAR")
	)
	(segment
		(start 84.130896 -245.199916)
		(end 83.243674 -245.199916)
		(width 0.1016)
		(layer "F.Cu")
		(net "M_A_CPU1_SB_PAR")
	)
	(segment
		(start 59.870594 -247.04167)
		(end 59.913012 -247.04167)
		(width 0.101854)
		(layer "F.Cu")
		(net "M_A_CPU1_SB_PAR")
	)
	(segment
		(start 85.608668 -244.948202)
		(end 85.441028 -245.04523)
		(width 0.088646)
		(layer "F.Cu")
		(net "M_A_CPU1_SB_PAR")
	)
	(segment
		(start 74.27595 -247.187212)
		(end 74.142092 -247.053354)
		(width 0.1016)
		(layer "F.Cu")
		(net "M_A_CPU1_SB_PAR")
	)
	(segment
		(start 84.553044 -244.991636)
		(end 84.344764 -245.199916)
		(width 0.088646)
		(layer "F.Cu")
		(net "M_A_CPU1_SB_PAR")
	)
	(segment
		(start 57.503314 -246.616728)
		(end 58.439812 -246.616728)
		(width 0.20066)
		(layer "F.Cu")
		(net "M_A_CPU1_SB_PAR")
	)
	(segment
		(start 86.148672 -245.043706)
		(end 85.983064 -244.948202)
		(width 0.088646)
		(layer "F.Cu")
		(net "M_A_CPU1_SB_PAR")
	)
	(segment
		(start 59.822842 -247.050052)
		(end 59.862212 -247.050052)
		(width 0.101854)
		(layer "F.Cu")
		(net "M_A_CPU1_SB_PAR")
	)
	(segment
		(start 81.256378 -247.187212)
		(end 74.27595 -247.187212)
		(width 0.1016)
		(layer "F.Cu")
		(net "M_A_CPU1_SB_PAR")
	)
	(segment
		(start 74.142092 -247.053354)
		(end 72.65035 -247.053354)
		(width 0.1016)
		(layer "F.Cu")
		(net "M_A_CPU1_SB_PAR")
	)
	(segment
		(start 66.118994 -246.860822)
		(end 65.8749 -246.616728)
		(width 0.20066)
		(layer "F.Cu")
		(net "M_A_CPU1_SB_PAR")
	)
	(segment
		(start 71.967598 -247.053354)
		(end 71.775066 -246.860822)
		(width 0.20066)
		(layer "F.Cu")
		(net "M_A_CPU1_SB_PAR")
	)
	(segment
		(start 84.709254 -244.926866)
		(end 84.553044 -244.991636)
		(width 0.088646)
		(layer "F.Cu")
		(net "M_A_CPU1_SB_PAR")
	)
	(segment
		(start 86.601554 -244.917722)
		(end 86.38286 -245.043706)
		(width 0.088646)
		(layer "F.Cu")
		(net "M_A_CPU1_SB_PAR")
	)
	(segment
		(start 59.095132 -246.379746)
		(end 59.303412 -246.588026)
		(width 0.20066)
		(layer "F.Cu")
		(net "M_A_CPU1_SB_PAR")
	)
	(segment
		(start 87.675466 -245.27256)
		(end 87.420704 -245.017798)
		(width 0.088646)
		(layer "F.Cu")
		(net "M_A_CPU1_SB_PAR")
	)
	(segment
		(start 59.460638 -247.050052)
		(end 59.822842 -247.050052)
		(width 0.20066)
		(layer "F.Cu")
		(net "M_A_CPU1_SB_PAR")
	)
	(segment
		(start 84.963762 -244.926866)
		(end 84.709254 -244.926866)
		(width 0.088646)
		(layer "F.Cu")
		(net "M_A_CPU1_SB_PAR")
	)
	(segment
		(start 59.303412 -246.892826)
		(end 59.460638 -247.050052)
		(width 0.20066)
		(layer "F.Cu")
		(net "M_A_CPU1_SB_PAR")
	)
	(segment
		(start 85.22843 -245.048532)
		(end 85.043264 -244.948202)
		(width 0.088646)
		(layer "F.Cu")
		(net "M_A_CPU1_SB_PAR")
	)
	(segment
		(start 58.676794 -246.379746)
		(end 59.095132 -246.379746)
		(width 0.20066)
		(layer "F.Cu")
		(net "M_A_CPU1_SB_PAR")
	)
	(segment
		(start 59.913012 -247.04167)
		(end 62.046612 -247.04167)
		(width 0.1016)
		(layer "F.Cu")
		(net "M_A_CPU1_SB_PAR")
	)
	(segment
		(start 64.061086 -246.616728)
		(end 65.047114 -246.616728)
		(width 0.20066)
		(layer "F.Cu")
		(net "M_A_CPU1_SB_PAR")
	)
	(segment
		(start 62.147958 -247.04167)
		(end 63.636144 -247.04167)
		(width 0.20066)
		(layer "F.Cu")
		(net "M_A_CPU1_SB_PAR")
	)
	(segment
		(start 65.8749 -246.616728)
		(end 65.047114 -246.616728)
		(width 0.20066)
		(layer "F.Cu")
		(net "M_A_CPU1_SB_PAR")
	)
	(segment
		(start 84.344764 -245.199916)
		(end 84.130896 -245.199916)
		(width 0.088646)
		(layer "F.Cu")
		(net "M_A_CPU1_SB_PAR")
	)
	(segment
		(start 87.048086 -244.863366)
		(end 86.804246 -244.863366)
		(width 0.088646)
		(layer "F.Cu")
		(net "M_A_CPU1_SB_PAR")
	)
	(segment
		(start 71.775066 -246.860822)
		(end 66.118994 -246.860822)
		(width 0.20066)
		(layer "F.Cu")
		(net "M_A_CPU1_SB_PAR")
	)
	(segment
		(start 62.046612 -247.04167)
		(end 62.147958 -247.04167)
		(width 0.101854)
		(layer "F.Cu")
		(net "M_A_CPU1_SB_PAR")
	)
	(segment
		(start 83.243674 -245.199916)
		(end 81.256378 -247.187212)
		(width 0.1016)
		(layer "F.Cu")
		(net "M_A_CPU1_SB_PAR")
	)
	(segment
		(start 59.303412 -246.588026)
		(end 59.303412 -246.892826)
		(width 0.20066)
		(layer "F.Cu")
		(net "M_A_CPU1_SB_PAR")
	)
	(segment
		(start 59.862212 -247.050052)
		(end 59.870594 -247.04167)
		(width 0.101854)
		(layer "F.Cu")
		(net "M_A_CPU1_SB_PAR")
	)
	(segment
		(start 58.439812 -246.616728)
		(end 58.676794 -246.379746)
		(width 0.20066)
		(layer "F.Cu")
		(net "M_A_CPU1_SB_PAR")
	)
	(segment
		(start 72.65035 -247.053354)
		(end 71.967598 -247.053354)
		(width 0.20066)
		(layer "F.Cu")
		(net "M_A_CPU1_SB_PAR")
	)
	(arc
		(start 85.983064 -244.948202)
		(mid 85.795866 -244.898059)
		(end 85.608668 -244.948202)
		(width 0.088646)
		(layer "F.Cu")
		(net "M_A_CPU1_SB_PAR")
	)
	(arc
		(start 85.441028 -245.04523)
		(mid 85.335163 -245.074496)
		(end 85.22843 -245.048532)
		(width 0.088646)
		(layer "F.Cu")
		(net "M_A_CPU1_SB_PAR")
	)
	(arc
		(start 87.420704 -245.017798)
		(mid 87.24976 -244.903513)
		(end 87.048086 -244.863366)
		(width 0.088646)
		(layer "F.Cu")
		(net "M_A_CPU1_SB_PAR")
	)
	(arc
		(start 86.804246 -244.863366)
		(mid 86.69933 -244.877228)
		(end 86.601554 -244.917722)
		(width 0.088646)
		(layer "F.Cu")
		(net "M_A_CPU1_SB_PAR")
	)
	(arc
		(start 86.38286 -245.043706)
		(mid 86.265766 -245.075097)
		(end 86.148672 -245.043706)
		(width 0.088646)
		(layer "F.Cu")
		(net "M_A_CPU1_SB_PAR")
	)
	(arc
		(start 85.043264 -244.948202)
		(mid 85.004925 -244.932264)
		(end 84.963762 -244.926866)
		(width 0.088646)
		(layer "F.Cu")
		(net "M_A_CPU1_SB_PAR")
	)
	(segment
		(start 71.557896 -238.988854)
		(end 74.186542 -240.077752)
		(width 0.20066)
		(layer "F.Cu")
		(net "M_A_CPU1_SB_DQS_DP<9>")
	)
	(segment
		(start 63.28918 -238.290354)
		(end 63.540386 -238.54156)
		(width 0.20066)
		(layer "F.Cu")
		(net "M_A_CPU1_SB_DQS_DP<9>")
	)
	(segment
		(start 55.732426 -238.287814)
		(end 55.986426 -238.541814)
		(width 0.20066)
		(layer "F.Cu")
		(net "M_A_CPU1_SB_DQS_DP<9>")
	)
	(segment
		(start 74.188066 -240.07699)
		(end 75.065636 -240.44021)
		(width 0.20066)
		(layer "F.Cu")
		(net "M_A_CPU1_SB_DQS_DP<9>")
	)
	(segment
		(start 60.947046 -238.116618)
		(end 61.44133 -238.116618)
		(width 0.20066)
		(layer "F.Cu")
		(net "M_A_CPU1_SB_DQS_DP<9>")
	)
	(segment
		(start 84.495132 -240.616994)
		(end 84.583524 -240.705386)
		(width 0.088646)
		(layer "F.Cu")
		(net "M_A_CPU1_SB_DQS_DP<9>")
	)
	(segment
		(start 61.44133 -238.116618)
		(end 61.692536 -237.865412)
		(width 0.20066)
		(layer "F.Cu")
		(net "M_A_CPU1_SB_DQS_DP<9>")
	)
	(segment
		(start 61.692536 -237.865412)
		(end 62.21222 -237.865412)
		(width 0.20066)
		(layer "F.Cu")
		(net "M_A_CPU1_SB_DQS_DP<9>")
	)
	(segment
		(start 84.143596 -240.590324)
		(end 84.277962 -240.616994)
		(width 0.088646)
		(layer "F.Cu")
		(net "M_A_CPU1_SB_DQS_DP<9>")
	)
	(segment
		(start 59.476132 -238.236506)
		(end 59.664854 -238.158274)
		(width 0.20066)
		(layer "F.Cu")
		(net "M_A_CPU1_SB_DQS_DP<9>")
	)
	(segment
		(start 63.540386 -238.54156)
		(end 63.582296 -238.54156)
		(width 0.20066)
		(layer "F.Cu")
		(net "M_A_CPU1_SB_DQS_DP<9>")
	)
	(segment
		(start 82.959194 -240.40338)
		(end 82.991198 -240.371376)
		(width 0.088646)
		(layer "F.Cu")
		(net "M_A_CPU1_SB_DQS_DP<9>")
	)
	(segment
		(start 80.981296 -240.44021)
		(end 81.019396 -240.44021)
		(width 0.1524)
		(layer "F.Cu")
		(net "M_A_CPU1_SB_DQS_DP<9>")
	)
	(segment
		(start 54.243986 -237.865158)
		(end 54.626002 -237.865158)
		(width 0.20066)
		(layer "F.Cu")
		(net "M_A_CPU1_SB_DQS_DP<9>")
	)
	(segment
		(start 83.581494 -240.48339)
		(end 83.884008 -240.483136)
		(width 0.088646)
		(layer "F.Cu")
		(net "M_A_CPU1_SB_DQS_DP<9>")
	)
	(segment
		(start 68.102988 -238.988854)
		(end 71.557896 -238.988854)
		(width 0.20066)
		(layer "F.Cu")
		(net "M_A_CPU1_SB_DQS_DP<9>")
	)
	(segment
		(start 54.626002 -237.865158)
		(end 55.048658 -238.287814)
		(width 0.20066)
		(layer "F.Cu")
		(net "M_A_CPU1_SB_DQS_DP<9>")
	)
	(segment
		(start 63.582296 -238.54156)
		(end 66.51752 -238.54156)
		(width 0.1016)
		(layer "F.Cu")
		(net "M_A_CPU1_SB_DQS_DP<9>")
	)
	(segment
		(start 82.991198 -240.371376)
		(end 83.310984 -240.371376)
		(width 0.088646)
		(layer "F.Cu")
		(net "M_A_CPU1_SB_DQS_DP<9>")
	)
	(segment
		(start 74.186542 -240.077752)
		(end 74.188066 -240.07699)
		(width 0.20066)
		(layer "F.Cu")
		(net "M_A_CPU1_SB_DQS_DP<9>")
	)
	(segment
		(start 85.075268 -240.693956)
		(end 85.083904 -240.690146)
		(width 0.088646)
		(layer "F.Cu")
		(net "M_A_CPU1_SB_DQS_DP<9>")
	)
	(segment
		(start 83.884008 -240.483136)
		(end 84.143596 -240.590324)
		(width 0.088646)
		(layer "F.Cu")
		(net "M_A_CPU1_SB_DQS_DP<9>")
	)
	(segment
		(start 55.986426 -238.541814)
		(end 56.032146 -238.541814)
		(width 0.20066)
		(layer "F.Cu")
		(net "M_A_CPU1_SB_DQS_DP<9>")
	)
	(segment
		(start 60.11672 -237.834932)
		(end 60.398406 -238.116618)
		(width 0.20066)
		(layer "F.Cu")
		(net "M_A_CPU1_SB_DQS_DP<9>")
	)
	(segment
		(start 84.277962 -240.616994)
		(end 84.495132 -240.616994)
		(width 0.088646)
		(layer "F.Cu")
		(net "M_A_CPU1_SB_DQS_DP<9>")
	)
	(segment
		(start 82.937096 -240.40338)
		(end 82.959194 -240.40338)
		(width 0.088646)
		(layer "F.Cu")
		(net "M_A_CPU1_SB_DQS_DP<9>")
	)
	(segment
		(start 66.51752 -238.54156)
		(end 67.655694 -238.54156)
		(width 0.20066)
		(layer "F.Cu")
		(net "M_A_CPU1_SB_DQS_DP<9>")
	)
	(segment
		(start 75.065636 -240.44021)
		(end 80.981296 -240.44021)
		(width 0.20066)
		(layer "F.Cu")
		(net "M_A_CPU1_SB_DQS_DP<9>")
	)
	(segment
		(start 56.032146 -238.541814)
		(end 58.967878 -238.541814)
		(width 0.1016)
		(layer "F.Cu")
		(net "M_A_CPU1_SB_DQS_DP<9>")
	)
	(segment
		(start 62.637162 -238.290354)
		(end 63.28918 -238.290354)
		(width 0.20066)
		(layer "F.Cu")
		(net "M_A_CPU1_SB_DQS_DP<9>")
	)
	(segment
		(start 53.403246 -238.116618)
		(end 53.992526 -238.116618)
		(width 0.20066)
		(layer "F.Cu")
		(net "M_A_CPU1_SB_DQS_DP<9>")
	)
	(segment
		(start 84.667598 -240.740184)
		(end 84.673186 -240.741708)
		(width 0.088646)
		(layer "F.Cu")
		(net "M_A_CPU1_SB_DQS_DP<9>")
	)
	(segment
		(start 59.008264 -238.541814)
		(end 59.313572 -238.236506)
		(width 0.20066)
		(layer "F.Cu")
		(net "M_A_CPU1_SB_DQS_DP<9>")
	)
	(segment
		(start 59.664854 -238.158274)
		(end 59.988196 -237.834932)
		(width 0.20066)
		(layer "F.Cu")
		(net "M_A_CPU1_SB_DQS_DP<9>")
	)
	(segment
		(start 59.988196 -237.834932)
		(end 60.11672 -237.834932)
		(width 0.20066)
		(layer "F.Cu")
		(net "M_A_CPU1_SB_DQS_DP<9>")
	)
	(segment
		(start 58.967878 -238.541814)
		(end 59.008264 -238.541814)
		(width 0.20066)
		(layer "F.Cu")
		(net "M_A_CPU1_SB_DQS_DP<9>")
	)
	(segment
		(start 55.048658 -238.287814)
		(end 55.732426 -238.287814)
		(width 0.20066)
		(layer "F.Cu")
		(net "M_A_CPU1_SB_DQS_DP<9>")
	)
	(segment
		(start 81.056226 -240.40338)
		(end 82.937096 -240.40338)
		(width 0.1524)
		(layer "F.Cu")
		(net "M_A_CPU1_SB_DQS_DP<9>")
	)
	(segment
		(start 60.398406 -238.116618)
		(end 60.947046 -238.116618)
		(width 0.20066)
		(layer "F.Cu")
		(net "M_A_CPU1_SB_DQS_DP<9>")
	)
	(segment
		(start 84.81822 -240.75009)
		(end 84.939886 -240.732056)
		(width 0.088646)
		(layer "F.Cu")
		(net "M_A_CPU1_SB_DQS_DP<9>")
	)
	(segment
		(start 59.313572 -238.236506)
		(end 59.476132 -238.236506)
		(width 0.20066)
		(layer "F.Cu")
		(net "M_A_CPU1_SB_DQS_DP<9>")
	)
	(segment
		(start 81.019396 -240.44021)
		(end 81.056226 -240.40338)
		(width 0.1524)
		(layer "F.Cu")
		(net "M_A_CPU1_SB_DQS_DP<9>")
	)
	(segment
		(start 62.21222 -237.865412)
		(end 62.637162 -238.290354)
		(width 0.20066)
		(layer "F.Cu")
		(net "M_A_CPU1_SB_DQS_DP<9>")
	)
	(segment
		(start 67.655694 -238.54156)
		(end 68.102988 -238.988854)
		(width 0.20066)
		(layer "F.Cu")
		(net "M_A_CPU1_SB_DQS_DP<9>")
	)
	(segment
		(start 53.992526 -238.116618)
		(end 54.243986 -237.865158)
		(width 0.20066)
		(layer "F.Cu")
		(net "M_A_CPU1_SB_DQS_DP<9>")
	)
	(segment
		(start 85.706712 -240.389156)
		(end 85.795866 -240.389156)
		(width 0.088646)
		(layer "F.Cu")
		(net "M_A_CPU1_SB_DQS_DP<9>")
	)
	(segment
		(start 83.310984 -240.371376)
		(end 83.581494 -240.48339)
		(width 0.088646)
		(layer "F.Cu")
		(net "M_A_CPU1_SB_DQS_DP<9>")
	)
	(arc
		(start 85.083904 -240.690146)
		(mid 85.172216 -240.642251)
		(end 85.249766 -240.578386)
		(width 0.088646)
		(layer "F.Cu")
		(net "M_A_CPU1_SB_DQS_DP<9>")
	)
	(arc
		(start 84.583524 -240.705386)
		(mid 84.622097 -240.73116)
		(end 84.667598 -240.740184)
		(width 0.088646)
		(layer "F.Cu")
		(net "M_A_CPU1_SB_DQS_DP<9>")
	)
	(arc
		(start 84.673186 -240.741708)
		(mid 84.745273 -240.753329)
		(end 84.81822 -240.75009)
		(width 0.088646)
		(layer "F.Cu")
		(net "M_A_CPU1_SB_DQS_DP<9>")
	)
	(arc
		(start 84.939886 -240.732056)
		(mid 85.008788 -240.71731)
		(end 85.075268 -240.693956)
		(width 0.088646)
		(layer "F.Cu")
		(net "M_A_CPU1_SB_DQS_DP<9>")
	)
	(arc
		(start 85.249766 -240.578386)
		(mid 85.459415 -240.438303)
		(end 85.706712 -240.389156)
		(width 0.088646)
		(layer "F.Cu")
		(net "M_A_CPU1_SB_DQS_DP<9>")
	)
	(segment
		(start 85.172042 -220.38437)
		(end 85.172804 -220.384878)
		(width 0.088646)
		(layer "F.Cu")
		(net "M_A_CPU1_SB_DQS_DP<8>")
	)
	(segment
		(start 72.169782 -199.272906)
		(end 72.771762 -199.272906)
		(width 0.20066)
		(layer "F.Cu")
		(net "M_A_CPU1_SB_DQS_DP<8>")
	)
	(segment
		(start 72.896222 -199.148446)
		(end 73.498202 -199.148446)
		(width 0.20066)
		(layer "F.Cu")
		(net "M_A_CPU1_SB_DQS_DP<8>")
	)
	(segment
		(start 62.147704 -198.591678)
		(end 62.147958 -198.591932)
		(width 0.1016)
		(layer "F.Cu")
		(net "M_A_CPU1_SB_DQS_DP<8>")
	)
	(segment
		(start 82.38236 -207.10525)
		(end 82.808318 -207.531208)
		(width 0.20066)
		(layer "F.Cu")
		(net "M_A_CPU1_SB_DQS_DP<8>")
	)
	(segment
		(start 81.780888 -206.503778)
		(end 81.780888 -206.6798)
		(width 0.20066)
		(layer "F.Cu")
		(net "M_A_CPU1_SB_DQS_DP<8>")
	)
	(segment
		(start 85.165438 -220.381068)
		(end 85.166708 -220.381576)
		(width 0.088646)
		(layer "F.Cu")
		(net "M_A_CPU1_SB_DQS_DP<8>")
	)
	(segment
		(start 59.628786 -198.585328)
		(end 59.822842 -198.585328)
		(width 0.20066)
		(layer "F.Cu")
		(net "M_A_CPU1_SB_DQS_DP<8>")
	)
	(segment
		(start 78.698598 -203.59751)
		(end 79.124048 -204.02296)
		(width 0.20066)
		(layer "F.Cu")
		(net "M_A_CPU1_SB_DQS_DP<8>")
	)
	(segment
		(start 77.069188 -201.9681)
		(end 77.24521 -201.9681)
		(width 0.20066)
		(layer "F.Cu")
		(net "M_A_CPU1_SB_DQS_DP<8>")
	)
	(segment
		(start 86.630764 -220.855794)
		(end 86.735666 -220.855794)
		(width 0.088646)
		(layer "F.Cu")
		(net "M_A_CPU1_SB_DQS_DP<8>")
	)
	(segment
		(start 58.239152 -199.277986)
		(end 58.573416 -199.277986)
		(width 0.20066)
		(layer "F.Cu")
		(net "M_A_CPU1_SB_DQS_DP<8>")
	)
	(segment
		(start 57.977786 -199.01662)
		(end 58.239152 -199.277986)
		(width 0.20066)
		(layer "F.Cu")
		(net "M_A_CPU1_SB_DQS_DP<8>")
	)
	(segment
		(start 80.753458 -205.65237)
		(end 81.178908 -206.07782)
		(width 0.20066)
		(layer "F.Cu")
		(net "M_A_CPU1_SB_DQS_DP<8>")
	)
	(segment
		(start 71.443342 -199.148446)
		(end 72.045322 -199.148446)
		(width 0.20066)
		(layer "F.Cu")
		(net "M_A_CPU1_SB_DQS_DP<8>")
	)
	(segment
		(start 59.829192 -198.591678)
		(end 62.147704 -198.591678)
		(width 0.1016)
		(layer "F.Cu")
		(net "M_A_CPU1_SB_DQS_DP<8>")
	)
	(segment
		(start 78.27264 -202.99553)
		(end 78.698598 -203.421488)
		(width 0.20066)
		(layer "F.Cu")
		(net "M_A_CPU1_SB_DQS_DP<8>")
	)
	(segment
		(start 65.883028 -199.272906)
		(end 71.318882 -199.272906)
		(width 0.20066)
		(layer "F.Cu")
		(net "M_A_CPU1_SB_DQS_DP<8>")
	)
	(segment
		(start 86.542626 -220.767656)
		(end 86.630764 -220.855794)
		(width 0.088646)
		(layer "F.Cu")
		(net "M_A_CPU1_SB_DQS_DP<8>")
	)
	(segment
		(start 79.30007 -204.02296)
		(end 79.726028 -204.448918)
		(width 0.20066)
		(layer "F.Cu")
		(net "M_A_CPU1_SB_DQS_DP<8>")
	)
	(segment
		(start 85.141054 -220.36786)
		(end 85.141816 -220.368368)
		(width 0.088646)
		(layer "F.Cu")
		(net "M_A_CPU1_SB_DQS_DP<8>")
	)
	(segment
		(start 59.362848 -198.851266)
		(end 59.628786 -198.585328)
		(width 0.20066)
		(layer "F.Cu")
		(net "M_A_CPU1_SB_DQS_DP<8>")
	)
	(segment
		(start 84.74456 -220.175836)
		(end 84.929472 -220.175582)
		(width 0.088646)
		(layer "F.Cu")
		(net "M_A_CPU1_SB_DQS_DP<8>")
	)
	(segment
		(start 85.172804 -220.384878)
		(end 85.172804 -220.385132)
		(width 0.088646)
		(layer "F.Cu")
		(net "M_A_CPU1_SB_DQS_DP<8>")
	)
	(segment
		(start 62.147958 -198.591932)
		(end 62.271148 -198.591932)
		(width 0.20066)
		(layer "F.Cu")
		(net "M_A_CPU1_SB_DQS_DP<8>")
	)
	(segment
		(start 79.124048 -204.02296)
		(end 79.30007 -204.02296)
		(width 0.20066)
		(layer "F.Cu")
		(net "M_A_CPU1_SB_DQS_DP<8>")
	)
	(segment
		(start 64.306196 -199.277986)
		(end 64.567562 -199.01662)
		(width 0.20066)
		(layer "F.Cu")
		(net "M_A_CPU1_SB_DQS_DP<8>")
	)
	(segment
		(start 86.078314 -220.363796)
		(end 86.424262 -220.537024)
		(width 0.088646)
		(layer "F.Cu")
		(net "M_A_CPU1_SB_DQS_DP<8>")
	)
	(segment
		(start 57.503314 -199.01662)
		(end 57.977786 -199.01662)
		(width 0.20066)
		(layer "F.Cu")
		(net "M_A_CPU1_SB_DQS_DP<8>")
	)
	(segment
		(start 85.17128 -220.384116)
		(end 85.172042 -220.38437)
		(width 0.088646)
		(layer "F.Cu")
		(net "M_A_CPU1_SB_DQS_DP<8>")
	)
	(segment
		(start 85.172804 -220.385132)
		(end 85.173566 -220.38564)
		(width 0.088646)
		(layer "F.Cu")
		(net "M_A_CPU1_SB_DQS_DP<8>")
	)
	(segment
		(start 79.726028 -204.62494)
		(end 80.151478 -205.05039)
		(width 0.20066)
		(layer "F.Cu")
		(net "M_A_CPU1_SB_DQS_DP<8>")
	)
	(segment
		(start 84.69122 -214.108538)
		(end 84.69122 -214.593678)
		(width 0.1524)
		(layer "F.Cu")
		(net "M_A_CPU1_SB_DQS_DP<8>")
	)
	(segment
		(start 80.151478 -205.05039)
		(end 80.3275 -205.05039)
		(width 0.20066)
		(layer "F.Cu")
		(net "M_A_CPU1_SB_DQS_DP<8>")
	)
	(segment
		(start 85.141816 -220.368368)
		(end 85.164676 -220.38056)
		(width 0.088646)
		(layer "F.Cu")
		(net "M_A_CPU1_SB_DQS_DP<8>")
	)
	(segment
		(start 84.72805 -209.854292)
		(end 84.72805 -214.033608)
		(width 0.20066)
		(layer "F.Cu")
		(net "M_A_CPU1_SB_DQS_DP<8>")
	)
	(segment
		(start 77.24521 -201.9681)
		(end 77.671168 -202.394058)
		(width 0.20066)
		(layer "F.Cu")
		(net "M_A_CPU1_SB_DQS_DP<8>")
	)
	(segment
		(start 83.40979 -208.13268)
		(end 83.835494 -208.558384)
		(width 0.20066)
		(layer "F.Cu")
		(net "M_A_CPU1_SB_DQS_DP<8>")
	)
	(segment
		(start 85.173566 -220.38564)
		(end 85.181694 -220.389958)
		(width 0.088646)
		(layer "F.Cu")
		(net "M_A_CPU1_SB_DQS_DP<8>")
	)
	(segment
		(start 83.835494 -208.558384)
		(end 83.835494 -208.734406)
		(width 0.20066)
		(layer "F.Cu")
		(net "M_A_CPU1_SB_DQS_DP<8>")
	)
	(segment
		(start 58.573416 -199.277986)
		(end 59.000136 -198.851266)
		(width 0.20066)
		(layer "F.Cu")
		(net "M_A_CPU1_SB_DQS_DP<8>")
	)
	(segment
		(start 85.639656 -220.32341)
		(end 85.907626 -220.32341)
		(width 0.088646)
		(layer "F.Cu")
		(net "M_A_CPU1_SB_DQS_DP<8>")
	)
	(segment
		(start 86.424262 -220.537024)
		(end 86.542626 -220.767656)
		(width 0.088646)
		(layer "F.Cu")
		(net "M_A_CPU1_SB_DQS_DP<8>")
	)
	(segment
		(start 82.808318 -207.531208)
		(end 82.808318 -207.70723)
		(width 0.20066)
		(layer "F.Cu")
		(net "M_A_CPU1_SB_DQS_DP<8>")
	)
	(segment
		(start 76.041758 -200.94067)
		(end 76.21778 -200.94067)
		(width 0.20066)
		(layer "F.Cu")
		(net "M_A_CPU1_SB_DQS_DP<8>")
	)
	(segment
		(start 84.567522 -209.466434)
		(end 84.72805 -209.854292)
		(width 0.20066)
		(layer "F.Cu")
		(net "M_A_CPU1_SB_DQS_DP<8>")
	)
	(segment
		(start 63.037466 -198.863204)
		(end 63.658242 -199.277986)
		(width 0.20066)
		(layer "F.Cu")
		(net "M_A_CPU1_SB_DQS_DP<8>")
	)
	(segment
		(start 76.643738 -201.54265)
		(end 77.069188 -201.9681)
		(width 0.20066)
		(layer "F.Cu")
		(net "M_A_CPU1_SB_DQS_DP<8>")
	)
	(segment
		(start 72.045322 -199.148446)
		(end 72.169782 -199.272906)
		(width 0.20066)
		(layer "F.Cu")
		(net "M_A_CPU1_SB_DQS_DP<8>")
	)
	(segment
		(start 83.835494 -208.734406)
		(end 84.567522 -209.466434)
		(width 0.20066)
		(layer "F.Cu")
		(net "M_A_CPU1_SB_DQS_DP<8>")
	)
	(segment
		(start 81.178908 -206.07782)
		(end 81.35493 -206.07782)
		(width 0.20066)
		(layer "F.Cu")
		(net "M_A_CPU1_SB_DQS_DP<8>")
	)
	(segment
		(start 85.138514 -220.36659)
		(end 85.141054 -220.36786)
		(width 0.088646)
		(layer "F.Cu")
		(net "M_A_CPU1_SB_DQS_DP<8>")
	)
	(segment
		(start 85.164676 -220.38056)
		(end 85.165438 -220.381068)
		(width 0.088646)
		(layer "F.Cu")
		(net "M_A_CPU1_SB_DQS_DP<8>")
	)
	(segment
		(start 71.318882 -199.272906)
		(end 71.443342 -199.148446)
		(width 0.20066)
		(layer "F.Cu")
		(net "M_A_CPU1_SB_DQS_DP<8>")
	)
	(segment
		(start 82.206338 -207.10525)
		(end 82.38236 -207.10525)
		(width 0.20066)
		(layer "F.Cu")
		(net "M_A_CPU1_SB_DQS_DP<8>")
	)
	(segment
		(start 59.000136 -198.851266)
		(end 59.362848 -198.851266)
		(width 0.20066)
		(layer "F.Cu")
		(net "M_A_CPU1_SB_DQS_DP<8>")
	)
	(segment
		(start 81.35493 -206.07782)
		(end 81.780888 -206.503778)
		(width 0.20066)
		(layer "F.Cu")
		(net "M_A_CPU1_SB_DQS_DP<8>")
	)
	(segment
		(start 78.698598 -203.421488)
		(end 78.698598 -203.59751)
		(width 0.20066)
		(layer "F.Cu")
		(net "M_A_CPU1_SB_DQS_DP<8>")
	)
	(segment
		(start 65.626234 -199.01662)
		(end 65.626488 -199.016366)
		(width 0.20066)
		(layer "F.Cu")
		(net "M_A_CPU1_SB_DQS_DP<8>")
	)
	(segment
		(start 76.643738 -201.366628)
		(end 76.643738 -201.54265)
		(width 0.20066)
		(layer "F.Cu")
		(net "M_A_CPU1_SB_DQS_DP<8>")
	)
	(segment
		(start 83.509104 -218.895168)
		(end 84.144866 -219.53093)
		(width 0.1524)
		(layer "F.Cu")
		(net "M_A_CPU1_SB_DQS_DP<8>")
	)
	(segment
		(start 85.373464 -220.405198)
		(end 85.48116 -220.356176)
		(width 0.088646)
		(layer "F.Cu")
		(net "M_A_CPU1_SB_DQS_DP<8>")
	)
	(segment
		(start 62.54242 -198.863204)
		(end 63.037466 -198.863204)
		(width 0.20066)
		(layer "F.Cu")
		(net "M_A_CPU1_SB_DQS_DP<8>")
	)
	(segment
		(start 84.929472 -220.175582)
		(end 85.06079 -220.3069)
		(width 0.088646)
		(layer "F.Cu")
		(net "M_A_CPU1_SB_DQS_DP<8>")
	)
	(segment
		(start 65.626488 -199.016366)
		(end 65.883028 -199.272906)
		(width 0.20066)
		(layer "F.Cu")
		(net "M_A_CPU1_SB_DQS_DP<8>")
	)
	(segment
		(start 59.822842 -198.585328)
		(end 59.829192 -198.591678)
		(width 0.101854)
		(layer "F.Cu")
		(net "M_A_CPU1_SB_DQS_DP<8>")
	)
	(segment
		(start 81.780888 -206.6798)
		(end 82.206338 -207.10525)
		(width 0.20066)
		(layer "F.Cu")
		(net "M_A_CPU1_SB_DQS_DP<8>")
	)
	(segment
		(start 72.771762 -199.272906)
		(end 72.896222 -199.148446)
		(width 0.20066)
		(layer "F.Cu")
		(net "M_A_CPU1_SB_DQS_DP<8>")
	)
	(segment
		(start 83.509104 -215.775794)
		(end 83.509104 -218.895168)
		(width 0.1524)
		(layer "F.Cu")
		(net "M_A_CPU1_SB_DQS_DP<8>")
	)
	(segment
		(start 84.69122 -214.593678)
		(end 83.509104 -215.775794)
		(width 0.1524)
		(layer "F.Cu")
		(net "M_A_CPU1_SB_DQS_DP<8>")
	)
	(segment
		(start 73.498202 -199.148446)
		(end 73.622662 -199.272906)
		(width 0.20066)
		(layer "F.Cu")
		(net "M_A_CPU1_SB_DQS_DP<8>")
	)
	(segment
		(start 84.72805 -214.033608)
		(end 84.72805 -214.071708)
		(width 0.1524)
		(layer "F.Cu")
		(net "M_A_CPU1_SB_DQS_DP<8>")
	)
	(segment
		(start 84.16036 -219.591636)
		(end 84.74456 -220.175836)
		(width 0.088646)
		(layer "F.Cu")
		(net "M_A_CPU1_SB_DQS_DP<8>")
	)
	(segment
		(start 63.658242 -199.277986)
		(end 64.306196 -199.277986)
		(width 0.20066)
		(layer "F.Cu")
		(net "M_A_CPU1_SB_DQS_DP<8>")
	)
	(segment
		(start 85.166708 -220.381576)
		(end 85.17128 -220.384116)
		(width 0.088646)
		(layer "F.Cu")
		(net "M_A_CPU1_SB_DQS_DP<8>")
	)
	(segment
		(start 84.72805 -214.071708)
		(end 84.69122 -214.108538)
		(width 0.1524)
		(layer "F.Cu")
		(net "M_A_CPU1_SB_DQS_DP<8>")
	)
	(segment
		(start 78.096618 -202.99553)
		(end 78.27264 -202.99553)
		(width 0.20066)
		(layer "F.Cu")
		(net "M_A_CPU1_SB_DQS_DP<8>")
	)
	(segment
		(start 77.671168 -202.394058)
		(end 77.671168 -202.57008)
		(width 0.20066)
		(layer "F.Cu")
		(net "M_A_CPU1_SB_DQS_DP<8>")
	)
	(segment
		(start 79.726028 -204.448918)
		(end 79.726028 -204.62494)
		(width 0.20066)
		(layer "F.Cu")
		(net "M_A_CPU1_SB_DQS_DP<8>")
	)
	(segment
		(start 80.753458 -205.476348)
		(end 80.753458 -205.65237)
		(width 0.20066)
		(layer "F.Cu")
		(net "M_A_CPU1_SB_DQS_DP<8>")
	)
	(segment
		(start 80.3275 -205.05039)
		(end 80.753458 -205.476348)
		(width 0.20066)
		(layer "F.Cu")
		(net "M_A_CPU1_SB_DQS_DP<8>")
	)
	(segment
		(start 65.047114 -199.01662)
		(end 65.626234 -199.01662)
		(width 0.20066)
		(layer "F.Cu")
		(net "M_A_CPU1_SB_DQS_DP<8>")
	)
	(segment
		(start 82.808318 -207.70723)
		(end 83.233768 -208.13268)
		(width 0.20066)
		(layer "F.Cu")
		(net "M_A_CPU1_SB_DQS_DP<8>")
	)
	(segment
		(start 84.144866 -219.53093)
		(end 84.16036 -219.546424)
		(width 0.088646)
		(layer "F.Cu")
		(net "M_A_CPU1_SB_DQS_DP<8>")
	)
	(segment
		(start 62.271148 -198.591932)
		(end 62.54242 -198.863204)
		(width 0.20066)
		(layer "F.Cu")
		(net "M_A_CPU1_SB_DQS_DP<8>")
	)
	(segment
		(start 74.373994 -199.272906)
		(end 76.041758 -200.94067)
		(width 0.20066)
		(layer "F.Cu")
		(net "M_A_CPU1_SB_DQS_DP<8>")
	)
	(segment
		(start 64.567562 -199.01662)
		(end 65.047114 -199.01662)
		(width 0.20066)
		(layer "F.Cu")
		(net "M_A_CPU1_SB_DQS_DP<8>")
	)
	(segment
		(start 73.622662 -199.272906)
		(end 74.373994 -199.272906)
		(width 0.20066)
		(layer "F.Cu")
		(net "M_A_CPU1_SB_DQS_DP<8>")
	)
	(segment
		(start 76.21778 -200.94067)
		(end 76.643738 -201.366628)
		(width 0.20066)
		(layer "F.Cu")
		(net "M_A_CPU1_SB_DQS_DP<8>")
	)
	(segment
		(start 84.16036 -219.546424)
		(end 84.16036 -219.591636)
		(width 0.088646)
		(layer "F.Cu")
		(net "M_A_CPU1_SB_DQS_DP<8>")
	)
	(segment
		(start 83.233768 -208.13268)
		(end 83.40979 -208.13268)
		(width 0.20066)
		(layer "F.Cu")
		(net "M_A_CPU1_SB_DQS_DP<8>")
	)
	(segment
		(start 77.671168 -202.57008)
		(end 78.096618 -202.99553)
		(width 0.20066)
		(layer "F.Cu")
		(net "M_A_CPU1_SB_DQS_DP<8>")
	)
	(arc
		(start 85.48116 -220.356176)
		(mid 85.558726 -220.331667)
		(end 85.639656 -220.32341)
		(width 0.088646)
		(layer "F.Cu")
		(net "M_A_CPU1_SB_DQS_DP<8>")
	)
	(arc
		(start 85.181694 -220.389958)
		(mid 85.232269 -220.410308)
		(end 85.285834 -220.420438)
		(width 0.088646)
		(layer "F.Cu")
		(net "M_A_CPU1_SB_DQS_DP<8>")
	)
	(arc
		(start 85.06079 -220.3069)
		(mid 85.097696 -220.339291)
		(end 85.138514 -220.36659)
		(width 0.088646)
		(layer "F.Cu")
		(net "M_A_CPU1_SB_DQS_DP<8>")
	)
	(arc
		(start 85.907626 -220.32341)
		(mid 85.995331 -220.333635)
		(end 86.078314 -220.363796)
		(width 0.088646)
		(layer "F.Cu")
		(net "M_A_CPU1_SB_DQS_DP<8>")
	)
	(arc
		(start 85.285834 -220.420438)
		(mid 85.33064 -220.418512)
		(end 85.373464 -220.405198)
		(width 0.088646)
		(layer "F.Cu")
		(net "M_A_CPU1_SB_DQS_DP<8>")
	)
	(segment
		(start 86.066884 -230.126286)
		(end 86.067392 -230.126794)
		(width 0.088646)
		(layer "F.Cu")
		(net "M_A_CPU1_SB_DQS_DP<7>")
	)
	(segment
		(start 76.98613 -213.97976)
		(end 77.41158 -214.40521)
		(width 0.20066)
		(layer "F.Cu")
		(net "M_A_CPU1_SB_DQS_DP<7>")
	)
	(segment
		(start 76.98613 -213.803738)
		(end 76.98613 -213.97976)
		(width 0.20066)
		(layer "F.Cu")
		(net "M_A_CPU1_SB_DQS_DP<7>")
	)
	(segment
		(start 64.306196 -208.62798)
		(end 64.567562 -208.366614)
		(width 0.20066)
		(layer "F.Cu")
		(net "M_A_CPU1_SB_DQS_DP<7>")
	)
	(segment
		(start 65.584324 -208.366614)
		(end 66.008758 -208.791048)
		(width 0.20066)
		(layer "F.Cu")
		(net "M_A_CPU1_SB_DQS_DP<7>")
	)
	(segment
		(start 86.546436 -230.538274)
		(end 86.630764 -230.622602)
		(width 0.088646)
		(layer "F.Cu")
		(net "M_A_CPU1_SB_DQS_DP<7>")
	)
	(segment
		(start 68.891658 -208.791048)
		(end 69.016118 -208.666588)
		(width 0.20066)
		(layer "F.Cu")
		(net "M_A_CPU1_SB_DQS_DP<7>")
	)
	(segment
		(start 74.32929 -211.32292)
		(end 74.505312 -211.32292)
		(width 0.20066)
		(layer "F.Cu")
		(net "M_A_CPU1_SB_DQS_DP<7>")
	)
	(segment
		(start 80.445864 -224.613216)
		(end 80.445864 -226.752658)
		(width 0.1524)
		(layer "F.Cu")
		(net "M_A_CPU1_SB_DQS_DP<7>")
	)
	(segment
		(start 77.41158 -214.40521)
		(end 77.587602 -214.40521)
		(width 0.20066)
		(layer "F.Cu")
		(net "M_A_CPU1_SB_DQS_DP<7>")
	)
	(segment
		(start 78.43901 -215.43264)
		(end 78.465934 -215.459564)
		(width 0.1524)
		(layer "F.Cu")
		(net "M_A_CPU1_SB_DQS_DP<7>")
	)
	(segment
		(start 75.9587 -212.95233)
		(end 76.38415 -213.37778)
		(width 0.20066)
		(layer "F.Cu")
		(net "M_A_CPU1_SB_DQS_DP<7>")
	)
	(segment
		(start 75.35672 -212.35035)
		(end 75.532742 -212.35035)
		(width 0.20066)
		(layer "F.Cu")
		(net "M_A_CPU1_SB_DQS_DP<7>")
	)
	(segment
		(start 73.90384 -210.89747)
		(end 74.32929 -211.32292)
		(width 0.20066)
		(layer "F.Cu")
		(net "M_A_CPU1_SB_DQS_DP<7>")
	)
	(segment
		(start 67.438778 -208.791048)
		(end 67.563238 -208.666588)
		(width 0.20066)
		(layer "F.Cu")
		(net "M_A_CPU1_SB_DQS_DP<7>")
	)
	(segment
		(start 69.618098 -208.666588)
		(end 69.742558 -208.791048)
		(width 0.20066)
		(layer "F.Cu")
		(net "M_A_CPU1_SB_DQS_DP<7>")
	)
	(segment
		(start 74.505312 -211.32292)
		(end 74.93127 -211.748878)
		(width 0.20066)
		(layer "F.Cu")
		(net "M_A_CPU1_SB_DQS_DP<7>")
	)
	(segment
		(start 59.822842 -207.925924)
		(end 59.83859 -207.941672)
		(width 0.1016)
		(layer "F.Cu")
		(net "M_A_CPU1_SB_DQS_DP<7>")
	)
	(segment
		(start 62.769242 -208.205324)
		(end 63.233808 -208.205324)
		(width 0.20066)
		(layer "F.Cu")
		(net "M_A_CPU1_SB_DQS_DP<7>")
	)
	(segment
		(start 64.567562 -208.366614)
		(end 65.047114 -208.366614)
		(width 0.20066)
		(layer "F.Cu")
		(net "M_A_CPU1_SB_DQS_DP<7>")
	)
	(segment
		(start 78.840584 -216.915492)
		(end 78.840584 -223.007936)
		(width 0.1524)
		(layer "F.Cu")
		(net "M_A_CPU1_SB_DQS_DP<7>")
	)
	(segment
		(start 78.01356 -215.00719)
		(end 78.43901 -215.43264)
		(width 0.20066)
		(layer "F.Cu")
		(net "M_A_CPU1_SB_DQS_DP<7>")
	)
	(segment
		(start 62.137544 -207.941672)
		(end 62.147958 -207.931258)
		(width 0.1016)
		(layer "F.Cu")
		(net "M_A_CPU1_SB_DQS_DP<7>")
	)
	(segment
		(start 65.047114 -208.366614)
		(end 65.584324 -208.366614)
		(width 0.20066)
		(layer "F.Cu")
		(net "M_A_CPU1_SB_DQS_DP<7>")
	)
	(segment
		(start 68.289678 -208.791048)
		(end 68.891658 -208.791048)
		(width 0.20066)
		(layer "F.Cu")
		(net "M_A_CPU1_SB_DQS_DP<7>")
	)
	(segment
		(start 72.450452 -209.26806)
		(end 72.87641 -209.694018)
		(width 0.20066)
		(layer "F.Cu")
		(net "M_A_CPU1_SB_DQS_DP<7>")
	)
	(segment
		(start 71.195438 -208.791048)
		(end 71.797418 -208.791048)
		(width 0.20066)
		(layer "F.Cu")
		(net "M_A_CPU1_SB_DQS_DP<7>")
	)
	(segment
		(start 78.727046 -216.641426)
		(end 78.840584 -216.915492)
		(width 0.1524)
		(layer "F.Cu")
		(net "M_A_CPU1_SB_DQS_DP<7>")
	)
	(segment
		(start 76.38415 -213.37778)
		(end 76.560172 -213.37778)
		(width 0.20066)
		(layer "F.Cu")
		(net "M_A_CPU1_SB_DQS_DP<7>")
	)
	(segment
		(start 86.630764 -230.622602)
		(end 86.735666 -230.622602)
		(width 0.088646)
		(layer "F.Cu")
		(net "M_A_CPU1_SB_DQS_DP<7>")
	)
	(segment
		(start 59.458352 -207.925924)
		(end 59.822842 -207.925924)
		(width 0.20066)
		(layer "F.Cu")
		(net "M_A_CPU1_SB_DQS_DP<7>")
	)
	(segment
		(start 68.165218 -208.666588)
		(end 68.289678 -208.791048)
		(width 0.20066)
		(layer "F.Cu")
		(net "M_A_CPU1_SB_DQS_DP<7>")
	)
	(segment
		(start 78.46568 -215.510872)
		(end 78.727046 -215.772238)
		(width 0.1524)
		(layer "F.Cu")
		(net "M_A_CPU1_SB_DQS_DP<7>")
	)
	(segment
		(start 67.563238 -208.666588)
		(end 68.165218 -208.666588)
		(width 0.20066)
		(layer "F.Cu")
		(net "M_A_CPU1_SB_DQS_DP<7>")
	)
	(segment
		(start 76.560172 -213.37778)
		(end 76.98613 -213.803738)
		(width 0.20066)
		(layer "F.Cu")
		(net "M_A_CPU1_SB_DQS_DP<7>")
	)
	(segment
		(start 69.016118 -208.666588)
		(end 69.618098 -208.666588)
		(width 0.20066)
		(layer "F.Cu")
		(net "M_A_CPU1_SB_DQS_DP<7>")
	)
	(segment
		(start 75.9587 -212.776308)
		(end 75.9587 -212.95233)
		(width 0.20066)
		(layer "F.Cu")
		(net "M_A_CPU1_SB_DQS_DP<7>")
	)
	(segment
		(start 71.797418 -208.791048)
		(end 72.27443 -209.26806)
		(width 0.20066)
		(layer "F.Cu")
		(net "M_A_CPU1_SB_DQS_DP<7>")
	)
	(segment
		(start 59.83859 -207.941672)
		(end 62.137544 -207.941672)
		(width 0.1016)
		(layer "F.Cu")
		(net "M_A_CPU1_SB_DQS_DP<7>")
	)
	(segment
		(start 73.30186 -210.29549)
		(end 73.477882 -210.29549)
		(width 0.20066)
		(layer "F.Cu")
		(net "M_A_CPU1_SB_DQS_DP<7>")
	)
	(segment
		(start 74.93127 -211.748878)
		(end 74.93127 -211.9249)
		(width 0.20066)
		(layer "F.Cu")
		(net "M_A_CPU1_SB_DQS_DP<7>")
	)
	(segment
		(start 86.067392 -230.126794)
		(end 86.428326 -230.307134)
		(width 0.088646)
		(layer "F.Cu")
		(net "M_A_CPU1_SB_DQS_DP<7>")
	)
	(segment
		(start 57.503314 -208.366614)
		(end 57.977786 -208.366614)
		(width 0.20066)
		(layer "F.Cu")
		(net "M_A_CPU1_SB_DQS_DP<7>")
	)
	(segment
		(start 59.183016 -208.20126)
		(end 59.458352 -207.925924)
		(width 0.20066)
		(layer "F.Cu")
		(net "M_A_CPU1_SB_DQS_DP<7>")
	)
	(segment
		(start 72.27443 -209.26806)
		(end 72.450452 -209.26806)
		(width 0.20066)
		(layer "F.Cu")
		(net "M_A_CPU1_SB_DQS_DP<7>")
	)
	(segment
		(start 84.520786 -230.057452)
		(end 84.85632 -230.057452)
		(width 0.088646)
		(layer "F.Cu")
		(net "M_A_CPU1_SB_DQS_DP<7>")
	)
	(segment
		(start 70.344538 -208.791048)
		(end 70.468998 -208.666588)
		(width 0.20066)
		(layer "F.Cu")
		(net "M_A_CPU1_SB_DQS_DP<7>")
	)
	(segment
		(start 83.932014 -230.058214)
		(end 83.954112 -230.058214)
		(width 0.088646)
		(layer "F.Cu")
		(net "M_A_CPU1_SB_DQS_DP<7>")
	)
	(segment
		(start 86.428326 -230.307134)
		(end 86.546436 -230.538274)
		(width 0.088646)
		(layer "F.Cu")
		(net "M_A_CPU1_SB_DQS_DP<7>")
	)
	(segment
		(start 69.742558 -208.791048)
		(end 70.344538 -208.791048)
		(width 0.20066)
		(layer "F.Cu")
		(net "M_A_CPU1_SB_DQS_DP<7>")
	)
	(segment
		(start 71.070978 -208.666588)
		(end 71.195438 -208.791048)
		(width 0.20066)
		(layer "F.Cu")
		(net "M_A_CPU1_SB_DQS_DP<7>")
	)
	(segment
		(start 78.840584 -223.007936)
		(end 80.445864 -224.613216)
		(width 0.1524)
		(layer "F.Cu")
		(net "M_A_CPU1_SB_DQS_DP<7>")
	)
	(segment
		(start 62.495176 -207.931258)
		(end 62.769242 -208.205324)
		(width 0.20066)
		(layer "F.Cu")
		(net "M_A_CPU1_SB_DQS_DP<7>")
	)
	(segment
		(start 73.477882 -210.29549)
		(end 73.90384 -210.721448)
		(width 0.20066)
		(layer "F.Cu")
		(net "M_A_CPU1_SB_DQS_DP<7>")
	)
	(segment
		(start 72.87641 -209.87004)
		(end 73.30186 -210.29549)
		(width 0.20066)
		(layer "F.Cu")
		(net "M_A_CPU1_SB_DQS_DP<7>")
	)
	(segment
		(start 70.468998 -208.666588)
		(end 71.070978 -208.666588)
		(width 0.20066)
		(layer "F.Cu")
		(net "M_A_CPU1_SB_DQS_DP<7>")
	)
	(segment
		(start 77.587602 -214.40521)
		(end 78.01356 -214.831168)
		(width 0.20066)
		(layer "F.Cu")
		(net "M_A_CPU1_SB_DQS_DP<7>")
	)
	(segment
		(start 74.93127 -211.9249)
		(end 75.35672 -212.35035)
		(width 0.20066)
		(layer "F.Cu")
		(net "M_A_CPU1_SB_DQS_DP<7>")
	)
	(segment
		(start 78.465934 -215.459564)
		(end 78.46568 -215.510872)
		(width 0.1524)
		(layer "F.Cu")
		(net "M_A_CPU1_SB_DQS_DP<7>")
	)
	(segment
		(start 66.008758 -208.791048)
		(end 67.438778 -208.791048)
		(width 0.20066)
		(layer "F.Cu")
		(net "M_A_CPU1_SB_DQS_DP<7>")
	)
	(segment
		(start 83.985862 -230.089964)
		(end 84.488274 -230.089964)
		(width 0.088646)
		(layer "F.Cu")
		(net "M_A_CPU1_SB_DQS_DP<7>")
	)
	(segment
		(start 58.895996 -208.20126)
		(end 59.183016 -208.20126)
		(width 0.20066)
		(layer "F.Cu")
		(net "M_A_CPU1_SB_DQS_DP<7>")
	)
	(segment
		(start 58.469276 -208.62798)
		(end 58.895996 -208.20126)
		(width 0.20066)
		(layer "F.Cu")
		(net "M_A_CPU1_SB_DQS_DP<7>")
	)
	(segment
		(start 57.977786 -208.366614)
		(end 58.239152 -208.62798)
		(width 0.20066)
		(layer "F.Cu")
		(net "M_A_CPU1_SB_DQS_DP<7>")
	)
	(segment
		(start 72.87641 -209.694018)
		(end 72.87641 -209.87004)
		(width 0.20066)
		(layer "F.Cu")
		(net "M_A_CPU1_SB_DQS_DP<7>")
	)
	(segment
		(start 83.75142 -230.058214)
		(end 83.932014 -230.058214)
		(width 0.1524)
		(layer "F.Cu")
		(net "M_A_CPU1_SB_DQS_DP<7>")
	)
	(segment
		(start 73.90384 -210.721448)
		(end 73.90384 -210.89747)
		(width 0.20066)
		(layer "F.Cu")
		(net "M_A_CPU1_SB_DQS_DP<7>")
	)
	(segment
		(start 78.01356 -214.831168)
		(end 78.01356 -215.00719)
		(width 0.20066)
		(layer "F.Cu")
		(net "M_A_CPU1_SB_DQS_DP<7>")
	)
	(segment
		(start 84.488274 -230.089964)
		(end 84.520786 -230.057452)
		(width 0.088646)
		(layer "F.Cu")
		(net "M_A_CPU1_SB_DQS_DP<7>")
	)
	(segment
		(start 83.954112 -230.058214)
		(end 83.985862 -230.089964)
		(width 0.088646)
		(layer "F.Cu")
		(net "M_A_CPU1_SB_DQS_DP<7>")
	)
	(segment
		(start 75.532742 -212.35035)
		(end 75.9587 -212.776308)
		(width 0.20066)
		(layer "F.Cu")
		(net "M_A_CPU1_SB_DQS_DP<7>")
	)
	(segment
		(start 63.233808 -208.205324)
		(end 63.866268 -208.62798)
		(width 0.20066)
		(layer "F.Cu")
		(net "M_A_CPU1_SB_DQS_DP<7>")
	)
	(segment
		(start 63.866268 -208.62798)
		(end 64.306196 -208.62798)
		(width 0.20066)
		(layer "F.Cu")
		(net "M_A_CPU1_SB_DQS_DP<7>")
	)
	(segment
		(start 80.445864 -226.752658)
		(end 83.75142 -230.058214)
		(width 0.1524)
		(layer "F.Cu")
		(net "M_A_CPU1_SB_DQS_DP<7>")
	)
	(segment
		(start 78.727046 -215.772238)
		(end 78.727046 -216.641426)
		(width 0.1524)
		(layer "F.Cu")
		(net "M_A_CPU1_SB_DQS_DP<7>")
	)
	(segment
		(start 58.239152 -208.62798)
		(end 58.469276 -208.62798)
		(width 0.20066)
		(layer "F.Cu")
		(net "M_A_CPU1_SB_DQS_DP<7>")
	)
	(segment
		(start 62.147958 -207.931258)
		(end 62.495176 -207.931258)
		(width 0.20066)
		(layer "F.Cu")
		(net "M_A_CPU1_SB_DQS_DP<7>")
	)
	(arc
		(start 85.51291 -230.133144)
		(mid 85.789014 -230.057158)
		(end 86.066884 -230.126286)
		(width 0.088646)
		(layer "F.Cu")
		(net "M_A_CPU1_SB_DQS_DP<7>")
	)
	(arc
		(start 84.85632 -230.057452)
		(mid 84.874489 -230.057671)
		(end 84.892642 -230.058468)
		(width 0.088646)
		(layer "F.Cu")
		(net "M_A_CPU1_SB_DQS_DP<7>")
	)
	(arc
		(start 85.138514 -230.133144)
		(mid 85.325712 -230.183287)
		(end 85.51291 -230.133144)
		(width 0.088646)
		(layer "F.Cu")
		(net "M_A_CPU1_SB_DQS_DP<7>")
	)
	(arc
		(start 84.892642 -230.058468)
		(mid 85.01987 -230.081666)
		(end 85.138514 -230.133144)
		(width 0.088646)
		(layer "F.Cu")
		(net "M_A_CPU1_SB_DQS_DP<7>")
	)
	(segment
		(start 85.139276 -235.017056)
		(end 85.15096 -235.024168)
		(width 0.088646)
		(layer "F.Cu")
		(net "M_A_CPU1_SB_DQS_DP<6>")
	)
	(segment
		(start 86.630764 -235.506006)
		(end 86.735666 -235.506006)
		(width 0.088646)
		(layer "F.Cu")
		(net "M_A_CPU1_SB_DQS_DP<6>")
	)
	(segment
		(start 67.88023 -218.290394)
		(end 68.46697 -218.877134)
		(width 0.20066)
		(layer "F.Cu")
		(net "M_A_CPU1_SB_DQS_DP<6>")
	)
	(segment
		(start 66.033396 -218.113356)
		(end 66.155824 -218.235784)
		(width 0.20066)
		(layer "F.Cu")
		(net "M_A_CPU1_SB_DQS_DP<6>")
	)
	(segment
		(start 86.42858 -235.190538)
		(end 86.528656 -235.38688)
		(width 0.088646)
		(layer "F.Cu")
		(net "M_A_CPU1_SB_DQS_DP<6>")
	)
	(segment
		(start 59.822842 -217.286332)
		(end 59.828176 -217.291666)
		(width 0.1016)
		(layer "F.Cu")
		(net "M_A_CPU1_SB_DQS_DP<6>")
	)
	(segment
		(start 57.977786 -217.716608)
		(end 58.239152 -217.977974)
		(width 0.20066)
		(layer "F.Cu")
		(net "M_A_CPU1_SB_DQS_DP<6>")
	)
	(segment
		(start 71.12381 -221.357952)
		(end 71.12381 -221.533974)
		(width 0.20066)
		(layer "F.Cu")
		(net "M_A_CPU1_SB_DQS_DP<6>")
	)
	(segment
		(start 71.67372 -226.453954)
		(end 71.54926 -226.578414)
		(width 0.20066)
		(layer "F.Cu")
		(net "M_A_CPU1_SB_DQS_DP<6>")
	)
	(segment
		(start 71.54926 -221.959424)
		(end 71.54926 -222.821754)
		(width 0.20066)
		(layer "F.Cu")
		(net "M_A_CPU1_SB_DQS_DP<6>")
	)
	(segment
		(start 71.54926 -222.821754)
		(end 71.67372 -222.946214)
		(width 0.20066)
		(layer "F.Cu")
		(net "M_A_CPU1_SB_DQS_DP<6>")
	)
	(segment
		(start 76.306172 -228.661468)
		(end 76.762102 -228.661468)
		(width 0.1524)
		(layer "F.Cu")
		(net "M_A_CPU1_SB_DQS_DP<6>")
	)
	(segment
		(start 65.047114 -217.716608)
		(end 65.841372 -217.716608)
		(width 0.20066)
		(layer "F.Cu")
		(net "M_A_CPU1_SB_DQS_DP<6>")
	)
	(segment
		(start 86.546436 -235.421678)
		(end 86.630764 -235.506006)
		(width 0.088646)
		(layer "F.Cu")
		(net "M_A_CPU1_SB_DQS_DP<6>")
	)
	(segment
		(start 71.67372 -223.548194)
		(end 71.54926 -223.672654)
		(width 0.20066)
		(layer "F.Cu")
		(net "M_A_CPU1_SB_DQS_DP<6>")
	)
	(segment
		(start 59.43219 -217.286332)
		(end 59.822842 -217.286332)
		(width 0.20066)
		(layer "F.Cu")
		(net "M_A_CPU1_SB_DQS_DP<6>")
	)
	(segment
		(start 74.051922 -228.500178)
		(end 74.176382 -228.624638)
		(width 0.20066)
		(layer "F.Cu")
		(net "M_A_CPU1_SB_DQS_DP<6>")
	)
	(segment
		(start 73.325482 -228.624638)
		(end 73.449942 -228.500178)
		(width 0.20066)
		(layer "F.Cu")
		(net "M_A_CPU1_SB_DQS_DP<6>")
	)
	(segment
		(start 82.920586 -234.819952)
		(end 83.470496 -234.819952)
		(width 0.1524)
		(layer "F.Cu")
		(net "M_A_CPU1_SB_DQS_DP<6>")
	)
	(segment
		(start 63.131192 -217.567002)
		(end 63.77432 -217.99677)
		(width 0.20066)
		(layer "F.Cu")
		(net "M_A_CPU1_SB_DQS_DP<6>")
	)
	(segment
		(start 65.841372 -217.716608)
		(end 66.033396 -217.908632)
		(width 0.20066)
		(layer "F.Cu")
		(net "M_A_CPU1_SB_DQS_DP<6>")
	)
	(segment
		(start 76.269342 -228.624638)
		(end 76.306172 -228.661468)
		(width 0.1524)
		(layer "F.Cu")
		(net "M_A_CPU1_SB_DQS_DP<6>")
	)
	(segment
		(start 70.52183 -220.931994)
		(end 70.697852 -220.931994)
		(width 0.20066)
		(layer "F.Cu")
		(net "M_A_CPU1_SB_DQS_DP<6>")
	)
	(segment
		(start 71.67372 -224.399094)
		(end 71.67372 -225.001074)
		(width 0.20066)
		(layer "F.Cu")
		(net "M_A_CPU1_SB_DQS_DP<6>")
	)
	(segment
		(start 72.283066 -227.597208)
		(end 72.709024 -228.023166)
		(width 0.20066)
		(layer "F.Cu")
		(net "M_A_CPU1_SB_DQS_DP<6>")
	)
	(segment
		(start 63.77432 -217.99677)
		(end 64.2874 -217.99677)
		(width 0.20066)
		(layer "F.Cu")
		(net "M_A_CPU1_SB_DQS_DP<6>")
	)
	(segment
		(start 62.446916 -217.2843)
		(end 62.729618 -217.567002)
		(width 0.20066)
		(layer "F.Cu")
		(net "M_A_CPU1_SB_DQS_DP<6>")
	)
	(segment
		(start 58.239152 -217.977974)
		(end 58.466736 -217.977974)
		(width 0.20066)
		(layer "F.Cu")
		(net "M_A_CPU1_SB_DQS_DP<6>")
	)
	(segment
		(start 57.503314 -217.716608)
		(end 57.977786 -217.716608)
		(width 0.20066)
		(layer "F.Cu")
		(net "M_A_CPU1_SB_DQS_DP<6>")
	)
	(segment
		(start 75.629262 -228.624638)
		(end 76.231242 -228.624638)
		(width 0.20066)
		(layer "F.Cu")
		(net "M_A_CPU1_SB_DQS_DP<6>")
	)
	(segment
		(start 62.147958 -217.2843)
		(end 62.446916 -217.2843)
		(width 0.20066)
		(layer "F.Cu")
		(net "M_A_CPU1_SB_DQS_DP<6>")
	)
	(segment
		(start 85.499194 -235.024676)
		(end 85.513164 -235.016548)
		(width 0.088646)
		(layer "F.Cu")
		(net "M_A_CPU1_SB_DQS_DP<6>")
	)
	(segment
		(start 71.54926 -223.672654)
		(end 71.54926 -224.274634)
		(width 0.20066)
		(layer "F.Cu")
		(net "M_A_CPU1_SB_DQS_DP<6>")
	)
	(segment
		(start 71.67372 -225.001074)
		(end 71.54926 -225.125534)
		(width 0.20066)
		(layer "F.Cu")
		(net "M_A_CPU1_SB_DQS_DP<6>")
	)
	(segment
		(start 71.54926 -225.125534)
		(end 71.54926 -225.727514)
		(width 0.20066)
		(layer "F.Cu")
		(net "M_A_CPU1_SB_DQS_DP<6>")
	)
	(segment
		(start 69.06895 -219.479114)
		(end 69.4944 -219.904564)
		(width 0.20066)
		(layer "F.Cu")
		(net "M_A_CPU1_SB_DQS_DP<6>")
	)
	(segment
		(start 62.128908 -217.291666)
		(end 62.136274 -217.2843)
		(width 0.1016)
		(layer "F.Cu")
		(net "M_A_CPU1_SB_DQS_DP<6>")
	)
	(segment
		(start 59.167268 -217.551254)
		(end 59.43219 -217.286332)
		(width 0.20066)
		(layer "F.Cu")
		(net "M_A_CPU1_SB_DQS_DP<6>")
	)
	(segment
		(start 64.2874 -217.99677)
		(end 64.567562 -217.716608)
		(width 0.20066)
		(layer "F.Cu")
		(net "M_A_CPU1_SB_DQS_DP<6>")
	)
	(segment
		(start 71.54926 -225.727514)
		(end 71.67372 -225.851974)
		(width 0.20066)
		(layer "F.Cu")
		(net "M_A_CPU1_SB_DQS_DP<6>")
	)
	(segment
		(start 71.67372 -225.851974)
		(end 71.67372 -226.453954)
		(width 0.20066)
		(layer "F.Cu")
		(net "M_A_CPU1_SB_DQS_DP<6>")
	)
	(segment
		(start 83.470496 -234.819952)
		(end 83.492594 -234.819952)
		(width 0.088646)
		(layer "F.Cu")
		(net "M_A_CPU1_SB_DQS_DP<6>")
	)
	(segment
		(start 74.176382 -228.624638)
		(end 74.778362 -228.624638)
		(width 0.20066)
		(layer "F.Cu")
		(net "M_A_CPU1_SB_DQS_DP<6>")
	)
	(segment
		(start 72.709024 -228.023166)
		(end 72.709024 -228.199188)
		(width 0.20066)
		(layer "F.Cu")
		(net "M_A_CPU1_SB_DQS_DP<6>")
	)
	(segment
		(start 69.4944 -219.904564)
		(end 69.670422 -219.904564)
		(width 0.20066)
		(layer "F.Cu")
		(net "M_A_CPU1_SB_DQS_DP<6>")
	)
	(segment
		(start 76.762102 -228.661468)
		(end 82.920586 -234.819952)
		(width 0.1524)
		(layer "F.Cu")
		(net "M_A_CPU1_SB_DQS_DP<6>")
	)
	(segment
		(start 83.492594 -234.819952)
		(end 83.524344 -234.851702)
		(width 0.088646)
		(layer "F.Cu")
		(net "M_A_CPU1_SB_DQS_DP<6>")
	)
	(segment
		(start 62.136274 -217.2843)
		(end 62.147958 -217.2843)
		(width 0.1016)
		(layer "F.Cu")
		(net "M_A_CPU1_SB_DQS_DP<6>")
	)
	(segment
		(start 71.54926 -226.578414)
		(end 71.54926 -227.039424)
		(width 0.20066)
		(layer "F.Cu")
		(net "M_A_CPU1_SB_DQS_DP<6>")
	)
	(segment
		(start 83.963002 -234.851702)
		(end 84.052156 -234.940856)
		(width 0.088646)
		(layer "F.Cu")
		(net "M_A_CPU1_SB_DQS_DP<6>")
	)
	(segment
		(start 70.697852 -220.931994)
		(end 71.12381 -221.357952)
		(width 0.20066)
		(layer "F.Cu")
		(net "M_A_CPU1_SB_DQS_DP<6>")
	)
	(segment
		(start 70.09638 -220.330522)
		(end 70.09638 -220.506544)
		(width 0.20066)
		(layer "F.Cu")
		(net "M_A_CPU1_SB_DQS_DP<6>")
	)
	(segment
		(start 59.828176 -217.291666)
		(end 62.128908 -217.291666)
		(width 0.1016)
		(layer "F.Cu")
		(net "M_A_CPU1_SB_DQS_DP<6>")
	)
	(segment
		(start 62.729618 -217.567002)
		(end 63.131192 -217.567002)
		(width 0.20066)
		(layer "F.Cu")
		(net "M_A_CPU1_SB_DQS_DP<6>")
	)
	(segment
		(start 66.231008 -218.235784)
		(end 66.57086 -218.09583)
		(width 0.20066)
		(layer "F.Cu")
		(net "M_A_CPU1_SB_DQS_DP<6>")
	)
	(segment
		(start 66.033396 -217.908632)
		(end 66.033396 -218.113356)
		(width 0.20066)
		(layer "F.Cu")
		(net "M_A_CPU1_SB_DQS_DP<6>")
	)
	(segment
		(start 66.57086 -218.09583)
		(end 67.410584 -218.09583)
		(width 0.20066)
		(layer "F.Cu")
		(net "M_A_CPU1_SB_DQS_DP<6>")
	)
	(segment
		(start 72.709024 -228.199188)
		(end 73.134474 -228.624638)
		(width 0.20066)
		(layer "F.Cu")
		(net "M_A_CPU1_SB_DQS_DP<6>")
	)
	(segment
		(start 64.567562 -217.716608)
		(end 65.047114 -217.716608)
		(width 0.20066)
		(layer "F.Cu")
		(net "M_A_CPU1_SB_DQS_DP<6>")
	)
	(segment
		(start 71.54926 -224.274634)
		(end 71.67372 -224.399094)
		(width 0.20066)
		(layer "F.Cu")
		(net "M_A_CPU1_SB_DQS_DP<6>")
	)
	(segment
		(start 71.54926 -227.039424)
		(end 72.107044 -227.597208)
		(width 0.20066)
		(layer "F.Cu")
		(net "M_A_CPU1_SB_DQS_DP<6>")
	)
	(segment
		(start 67.410584 -218.09583)
		(end 67.88023 -218.290394)
		(width 0.20066)
		(layer "F.Cu")
		(net "M_A_CPU1_SB_DQS_DP<6>")
	)
	(segment
		(start 73.449942 -228.500178)
		(end 74.051922 -228.500178)
		(width 0.20066)
		(layer "F.Cu")
		(net "M_A_CPU1_SB_DQS_DP<6>")
	)
	(segment
		(start 71.12381 -221.533974)
		(end 71.54926 -221.959424)
		(width 0.20066)
		(layer "F.Cu")
		(net "M_A_CPU1_SB_DQS_DP<6>")
	)
	(segment
		(start 68.642992 -218.877134)
		(end 69.06895 -219.303092)
		(width 0.20066)
		(layer "F.Cu")
		(net "M_A_CPU1_SB_DQS_DP<6>")
	)
	(segment
		(start 71.67372 -222.946214)
		(end 71.67372 -223.548194)
		(width 0.20066)
		(layer "F.Cu")
		(net "M_A_CPU1_SB_DQS_DP<6>")
	)
	(segment
		(start 69.06895 -219.303092)
		(end 69.06895 -219.479114)
		(width 0.20066)
		(layer "F.Cu")
		(net "M_A_CPU1_SB_DQS_DP<6>")
	)
	(segment
		(start 86.528656 -235.38688)
		(end 86.546436 -235.421678)
		(width 0.088646)
		(layer "F.Cu")
		(net "M_A_CPU1_SB_DQS_DP<6>")
	)
	(segment
		(start 83.524344 -234.851702)
		(end 83.963002 -234.851702)
		(width 0.088646)
		(layer "F.Cu")
		(net "M_A_CPU1_SB_DQS_DP<6>")
	)
	(segment
		(start 73.134474 -228.624638)
		(end 73.325482 -228.624638)
		(width 0.20066)
		(layer "F.Cu")
		(net "M_A_CPU1_SB_DQS_DP<6>")
	)
	(segment
		(start 68.46697 -218.877134)
		(end 68.642992 -218.877134)
		(width 0.20066)
		(layer "F.Cu")
		(net "M_A_CPU1_SB_DQS_DP<6>")
	)
	(segment
		(start 72.107044 -227.597208)
		(end 72.283066 -227.597208)
		(width 0.20066)
		(layer "F.Cu")
		(net "M_A_CPU1_SB_DQS_DP<6>")
	)
	(segment
		(start 58.466736 -217.977974)
		(end 58.893456 -217.551254)
		(width 0.20066)
		(layer "F.Cu")
		(net "M_A_CPU1_SB_DQS_DP<6>")
	)
	(segment
		(start 75.504802 -228.500178)
		(end 75.629262 -228.624638)
		(width 0.20066)
		(layer "F.Cu")
		(net "M_A_CPU1_SB_DQS_DP<6>")
	)
	(segment
		(start 86.0679 -235.010198)
		(end 86.42858 -235.190538)
		(width 0.088646)
		(layer "F.Cu")
		(net "M_A_CPU1_SB_DQS_DP<6>")
	)
	(segment
		(start 76.231242 -228.624638)
		(end 76.269342 -228.624638)
		(width 0.1524)
		(layer "F.Cu")
		(net "M_A_CPU1_SB_DQS_DP<6>")
	)
	(segment
		(start 74.778362 -228.624638)
		(end 74.902822 -228.500178)
		(width 0.20066)
		(layer "F.Cu")
		(net "M_A_CPU1_SB_DQS_DP<6>")
	)
	(segment
		(start 69.670422 -219.904564)
		(end 70.09638 -220.330522)
		(width 0.20066)
		(layer "F.Cu")
		(net "M_A_CPU1_SB_DQS_DP<6>")
	)
	(segment
		(start 58.893456 -217.551254)
		(end 59.167268 -217.551254)
		(width 0.20066)
		(layer "F.Cu")
		(net "M_A_CPU1_SB_DQS_DP<6>")
	)
	(segment
		(start 84.052156 -234.940856)
		(end 84.856574 -234.940856)
		(width 0.088646)
		(layer "F.Cu")
		(net "M_A_CPU1_SB_DQS_DP<6>")
	)
	(segment
		(start 66.155824 -218.235784)
		(end 66.231008 -218.235784)
		(width 0.20066)
		(layer "F.Cu")
		(net "M_A_CPU1_SB_DQS_DP<6>")
	)
	(segment
		(start 74.902822 -228.500178)
		(end 75.504802 -228.500178)
		(width 0.20066)
		(layer "F.Cu")
		(net "M_A_CPU1_SB_DQS_DP<6>")
	)
	(segment
		(start 70.09638 -220.506544)
		(end 70.52183 -220.931994)
		(width 0.20066)
		(layer "F.Cu")
		(net "M_A_CPU1_SB_DQS_DP<6>")
	)
	(arc
		(start 85.15096 -235.024168)
		(mid 85.325003 -235.067235)
		(end 85.499194 -235.024676)
		(width 0.088646)
		(layer "F.Cu")
		(net "M_A_CPU1_SB_DQS_DP<6>")
	)
	(arc
		(start 85.513164 -235.016548)
		(mid 85.789693 -234.940681)
		(end 86.0679 -235.010198)
		(width 0.088646)
		(layer "F.Cu")
		(net "M_A_CPU1_SB_DQS_DP<6>")
	)
	(arc
		(start 84.892388 -234.941872)
		(mid 85.020181 -234.965182)
		(end 85.139276 -235.017056)
		(width 0.088646)
		(layer "F.Cu")
		(net "M_A_CPU1_SB_DQS_DP<6>")
	)
	(arc
		(start 84.856574 -234.940856)
		(mid 84.874489 -234.941084)
		(end 84.892388 -234.941872)
		(width 0.088646)
		(layer "F.Cu")
		(net "M_A_CPU1_SB_DQS_DP<6>")
	)
	(segment
		(start 63.189866 -226.927918)
		(end 62.557152 -226.927918)
		(width 0.20066)
		(layer "F.Cu")
		(net "M_A_CPU1_SB_DQS_DP<5>")
	)
	(segment
		(start 62.147958 -226.641914)
		(end 62.147704 -226.64166)
		(width 0.1016)
		(layer "F.Cu")
		(net "M_A_CPU1_SB_DQS_DP<5>")
	)
	(segment
		(start 59.844686 -226.63023)
		(end 59.822842 -226.63023)
		(width 0.101854)
		(layer "F.Cu")
		(net "M_A_CPU1_SB_DQS_DP<5>")
	)
	(segment
		(start 90.964766 -237.9472)
		(end 90.964766 -237.411514)
		(width 0.20066)
		(layer "F.Cu")
		(net "M_A_CPU1_SB_DQS_DP<5>")
	)
	(segment
		(start 58.992516 -226.908868)
		(end 58.573416 -227.327968)
		(width 0.20066)
		(layer "F.Cu")
		(net "M_A_CPU1_SB_DQS_DP<5>")
	)
	(segment
		(start 59.822842 -226.63023)
		(end 59.633866 -226.63023)
		(width 0.20066)
		(layer "F.Cu")
		(net "M_A_CPU1_SB_DQS_DP<5>")
	)
	(segment
		(start 64.567562 -227.066602)
		(end 64.306196 -227.327968)
		(width 0.20066)
		(layer "F.Cu")
		(net "M_A_CPU1_SB_DQS_DP<5>")
	)
	(segment
		(start 62.147704 -226.64166)
		(end 59.893454 -226.64166)
		(width 0.1016)
		(layer "F.Cu")
		(net "M_A_CPU1_SB_DQS_DP<5>")
	)
	(segment
		(start 62.271148 -226.641914)
		(end 62.147958 -226.641914)
		(width 0.20066)
		(layer "F.Cu")
		(net "M_A_CPU1_SB_DQS_DP<5>")
	)
	(segment
		(start 58.239152 -227.327968)
		(end 57.977786 -227.066602)
		(width 0.20066)
		(layer "F.Cu")
		(net "M_A_CPU1_SB_DQS_DP<5>")
	)
	(segment
		(start 90.964512 -237.947454)
		(end 90.964766 -237.9472)
		(width 0.20066)
		(layer "F.Cu")
		(net "M_A_CPU1_SB_DQS_DP<5>")
	)
	(segment
		(start 59.893454 -226.64166)
		(end 59.844686 -226.63023)
		(width 0.1016)
		(layer "F.Cu")
		(net "M_A_CPU1_SB_DQS_DP<5>")
	)
	(segment
		(start 57.977786 -227.066602)
		(end 57.503314 -227.066602)
		(width 0.20066)
		(layer "F.Cu")
		(net "M_A_CPU1_SB_DQS_DP<5>")
	)
	(segment
		(start 62.557152 -226.927918)
		(end 62.271148 -226.641914)
		(width 0.20066)
		(layer "F.Cu")
		(net "M_A_CPU1_SB_DQS_DP<5>")
	)
	(segment
		(start 58.573416 -227.327968)
		(end 58.239152 -227.327968)
		(width 0.20066)
		(layer "F.Cu")
		(net "M_A_CPU1_SB_DQS_DP<5>")
	)
	(segment
		(start 63.788798 -227.327968)
		(end 63.189866 -226.927918)
		(width 0.20066)
		(layer "F.Cu")
		(net "M_A_CPU1_SB_DQS_DP<5>")
	)
	(segment
		(start 64.306196 -227.327968)
		(end 63.788798 -227.327968)
		(width 0.20066)
		(layer "F.Cu")
		(net "M_A_CPU1_SB_DQS_DP<5>")
	)
	(segment
		(start 59.633866 -226.63023)
		(end 59.355228 -226.908868)
		(width 0.20066)
		(layer "F.Cu")
		(net "M_A_CPU1_SB_DQS_DP<5>")
	)
	(segment
		(start 66.152014 -227.066602)
		(end 65.047114 -227.066602)
		(width 0.20066)
		(layer "F.Cu")
		(net "M_A_CPU1_SB_DQS_DP<5>")
	)
	(segment
		(start 65.047114 -227.066602)
		(end 64.567562 -227.066602)
		(width 0.20066)
		(layer "F.Cu")
		(net "M_A_CPU1_SB_DQS_DP<5>")
	)
	(segment
		(start 59.355228 -226.908868)
		(end 58.992516 -226.908868)
		(width 0.20066)
		(layer "F.Cu")
		(net "M_A_CPU1_SB_DQS_DP<5>")
	)
	(segment
		(start 70.73138 -227.344732)
		(end 66.430144 -227.344732)
		(width 0.18288)
		(layer "In2.Cu")
		(net "M_A_CPU1_SB_DQS_DP<5>")
	)
	(segment
		(start 87.862664 -236.922056)
		(end 87.851742 -236.928406)
		(width 0.088646)
		(layer "In2.Cu")
		(net "M_A_CPU1_SB_DQS_DP<5>")
	)
	(segment
		(start 82.79257 -236.917992)
		(end 80.297528 -236.917992)
		(width 0.18288)
		(layer "In2.Cu")
		(net "M_A_CPU1_SB_DQS_DP<5>")
	)
	(segment
		(start 82.852514 -236.977936)
		(end 82.79257 -236.917992)
		(width 0.088646)
		(layer "In2.Cu")
		(net "M_A_CPU1_SB_DQS_DP<5>")
	)
	(segment
		(start 90.31351 -236.925612)
		(end 90.307414 -236.922056)
		(width 0.088646)
		(layer "In2.Cu")
		(net "M_A_CPU1_SB_DQS_DP<5>")
	)
	(segment
		(start 90.307414 -236.922056)
		(end 90.292682 -236.91342)
		(width 0.088646)
		(layer "In2.Cu")
		(net "M_A_CPU1_SB_DQS_DP<5>")
	)
	(segment
		(start 90.964766 -237.411514)
		(end 90.651838 -237.411514)
		(width 0.088646)
		(layer "In2.Cu")
		(net "M_A_CPU1_SB_DQS_DP<5>")
	)
	(segment
		(start 83.85556 -236.977936)
		(end 82.852514 -236.977936)
		(width 0.088646)
		(layer "In2.Cu")
		(net "M_A_CPU1_SB_DQS_DP<5>")
	)
	(segment
		(start 90.651838 -237.411514)
		(end 90.586306 -237.345982)
		(width 0.088646)
		(layer "In2.Cu")
		(net "M_A_CPU1_SB_DQS_DP<5>")
	)
	(segment
		(start 70.727824 -227.348288)
		(end 70.73138 -227.344732)
		(width 0.18288)
		(layer "In2.Cu")
		(net "M_A_CPU1_SB_DQS_DP<5>")
	)
	(segment
		(start 89.367614 -236.922056)
		(end 89.3572 -236.91596)
		(width 0.088646)
		(layer "In2.Cu")
		(net "M_A_CPU1_SB_DQS_DP<5>")
	)
	(segment
		(start 66.430144 -227.344732)
		(end 66.152014 -227.066602)
		(width 0.18288)
		(layer "In2.Cu")
		(net "M_A_CPU1_SB_DQS_DP<5>")
	)
	(segment
		(start 85.057996 -236.913674)
		(end 85.043264 -236.92231)
		(width 0.088646)
		(layer "In2.Cu")
		(net "M_A_CPU1_SB_DQS_DP<5>")
	)
	(segment
		(start 86.937596 -236.913674)
		(end 86.922864 -236.92231)
		(width 0.088646)
		(layer "In2.Cu")
		(net "M_A_CPU1_SB_DQS_DP<5>")
	)
	(segment
		(start 80.297528 -236.917992)
		(end 70.727824 -227.348288)
		(width 0.18288)
		(layer "In2.Cu")
		(net "M_A_CPU1_SB_DQS_DP<5>")
	)
	(arc
		(start 86.548468 -236.92231)
		(mid 86.265766 -236.846534)
		(end 85.983064 -236.92231)
		(width 0.088646)
		(layer "In2.Cu")
		(net "M_A_CPU1_SB_DQS_DP<5>")
	)
	(arc
		(start 87.851742 -236.928406)
		(mid 87.669212 -236.97243)
		(end 87.488268 -236.92231)
		(width 0.088646)
		(layer "In2.Cu")
		(net "M_A_CPU1_SB_DQS_DP<5>")
	)
	(arc
		(start 90.292682 -236.91342)
		(mid 90.016207 -236.8461)
		(end 89.74201 -236.922056)
		(width 0.088646)
		(layer "In2.Cu")
		(net "M_A_CPU1_SB_DQS_DP<5>")
	)
	(arc
		(start 85.608668 -236.92231)
		(mid 85.334469 -236.846475)
		(end 85.057996 -236.913674)
		(width 0.088646)
		(layer "In2.Cu")
		(net "M_A_CPU1_SB_DQS_DP<5>")
	)
	(arc
		(start 84.289138 -236.854492)
		(mid 84.202387 -236.876599)
		(end 84.120228 -236.91215)
		(width 0.088646)
		(layer "In2.Cu")
		(net "M_A_CPU1_SB_DQS_DP<5>")
	)
	(arc
		(start 84.668868 -236.92231)
		(mid 84.484964 -236.855068)
		(end 84.289138 -236.854492)
		(width 0.088646)
		(layer "In2.Cu")
		(net "M_A_CPU1_SB_DQS_DP<5>")
	)
	(arc
		(start 88.802464 -236.922056)
		(mid 88.615266 -236.972233)
		(end 88.428068 -236.922056)
		(width 0.088646)
		(layer "In2.Cu")
		(net "M_A_CPU1_SB_DQS_DP<5>")
	)
	(arc
		(start 84.120228 -236.91215)
		(mid 83.991923 -236.961255)
		(end 83.85556 -236.977936)
		(width 0.088646)
		(layer "In2.Cu")
		(net "M_A_CPU1_SB_DQS_DP<5>")
	)
	(arc
		(start 88.428068 -236.922056)
		(mid 88.145366 -236.84628)
		(end 87.862664 -236.922056)
		(width 0.088646)
		(layer "In2.Cu")
		(net "M_A_CPU1_SB_DQS_DP<5>")
	)
	(arc
		(start 90.586306 -237.345982)
		(mid 90.499062 -237.103894)
		(end 90.31351 -236.925612)
		(width 0.088646)
		(layer "In2.Cu")
		(net "M_A_CPU1_SB_DQS_DP<5>")
	)
	(arc
		(start 86.922864 -236.92231)
		(mid 86.735666 -236.972453)
		(end 86.548468 -236.92231)
		(width 0.088646)
		(layer "In2.Cu")
		(net "M_A_CPU1_SB_DQS_DP<5>")
	)
	(arc
		(start 85.043264 -236.92231)
		(mid 84.856066 -236.972453)
		(end 84.668868 -236.92231)
		(width 0.088646)
		(layer "In2.Cu")
		(net "M_A_CPU1_SB_DQS_DP<5>")
	)
	(arc
		(start 85.983064 -236.92231)
		(mid 85.795866 -236.972453)
		(end 85.608668 -236.92231)
		(width 0.088646)
		(layer "In2.Cu")
		(net "M_A_CPU1_SB_DQS_DP<5>")
	)
	(arc
		(start 89.3572 -236.91596)
		(mid 89.079022 -236.846237)
		(end 88.802464 -236.922056)
		(width 0.088646)
		(layer "In2.Cu")
		(net "M_A_CPU1_SB_DQS_DP<5>")
	)
	(arc
		(start 87.488268 -236.92231)
		(mid 87.214069 -236.846475)
		(end 86.937596 -236.913674)
		(width 0.088646)
		(layer "In2.Cu")
		(net "M_A_CPU1_SB_DQS_DP<5>")
	)
	(arc
		(start 89.74201 -236.922056)
		(mid 89.554812 -236.972233)
		(end 89.367614 -236.922056)
		(width 0.088646)
		(layer "In2.Cu")
		(net "M_A_CPU1_SB_DQS_DP<5>")
	)
	(segment
		(start 70.057518 -237.368588)
		(end 70.659498 -237.368588)
		(width 0.20066)
		(layer "F.Cu")
		(net "M_A_CPU1_SB_DQS_DP<4>")
	)
	(segment
		(start 59.362848 -236.251242)
		(end 59.622436 -235.991654)
		(width 0.20066)
		(layer "F.Cu")
		(net "M_A_CPU1_SB_DQS_DP<4>")
	)
	(segment
		(start 74.222864 -238.223806)
		(end 74.329544 -238.117126)
		(width 0.20066)
		(layer "F.Cu")
		(net "M_A_CPU1_SB_DQS_DP<4>")
	)
	(segment
		(start 78.075536 -239.014)
		(end 78.199996 -238.88954)
		(width 0.20066)
		(layer "F.Cu")
		(net "M_A_CPU1_SB_DQS_DP<4>")
	)
	(segment
		(start 83.337654 -239.452658)
		(end 83.503516 -239.618774)
		(width 0.088646)
		(layer "F.Cu")
		(net "M_A_CPU1_SB_DQS_DP<4>")
	)
	(segment
		(start 72.529446 -237.531402)
		(end 73.08596 -237.762034)
		(width 0.20066)
		(layer "F.Cu")
		(net "M_A_CPU1_SB_DQS_DP<4>")
	)
	(segment
		(start 81.056226 -239.05083)
		(end 82.98053 -239.05083)
		(width 0.1524)
		(layer "F.Cu")
		(net "M_A_CPU1_SB_DQS_DP<4>")
	)
	(segment
		(start 75.702922 -237.712758)
		(end 75.702922 -238.882936)
		(width 0.20066)
		(layer "F.Cu")
		(net "M_A_CPU1_SB_DQS_DP<4>")
	)
	(segment
		(start 76.747116 -238.88954)
		(end 77.349096 -238.88954)
		(width 0.20066)
		(layer "F.Cu")
		(net "M_A_CPU1_SB_DQS_DP<4>")
	)
	(segment
		(start 57.977786 -236.416596)
		(end 58.239152 -236.677962)
		(width 0.20066)
		(layer "F.Cu")
		(net "M_A_CPU1_SB_DQS_DP<4>")
	)
	(segment
		(start 77.349096 -238.88954)
		(end 77.473556 -239.014)
		(width 0.20066)
		(layer "F.Cu")
		(net "M_A_CPU1_SB_DQS_DP<4>")
	)
	(segment
		(start 74.722228 -237.320074)
		(end 75.310238 -237.320074)
		(width 0.20066)
		(layer "F.Cu")
		(net "M_A_CPU1_SB_DQS_DP<4>")
	)
	(segment
		(start 79.528416 -239.014)
		(end 79.652876 -238.88954)
		(width 0.20066)
		(layer "F.Cu")
		(net "M_A_CPU1_SB_DQS_DP<4>")
	)
	(segment
		(start 67.498722 -236.785404)
		(end 67.623182 -236.909864)
		(width 0.20066)
		(layer "F.Cu")
		(net "M_A_CPU1_SB_DQS_DP<4>")
	)
	(segment
		(start 59.622436 -235.991654)
		(end 59.69889 -235.991654)
		(width 0.20066)
		(layer "F.Cu")
		(net "M_A_CPU1_SB_DQS_DP<4>")
	)
	(segment
		(start 83.337654 -239.407954)
		(end 83.337654 -239.452658)
		(width 0.088646)
		(layer "F.Cu")
		(net "M_A_CPU1_SB_DQS_DP<4>")
	)
	(segment
		(start 80.254856 -238.88954)
		(end 80.379316 -239.014)
		(width 0.20066)
		(layer "F.Cu")
		(net "M_A_CPU1_SB_DQS_DP<4>")
	)
	(segment
		(start 86.066884 -239.89284)
		(end 86.067392 -239.893348)
		(width 0.088646)
		(layer "F.Cu")
		(net "M_A_CPU1_SB_DQS_DP<4>")
	)
	(segment
		(start 62.769242 -236.255306)
		(end 63.233808 -236.255306)
		(width 0.20066)
		(layer "F.Cu")
		(net "M_A_CPU1_SB_DQS_DP<4>")
	)
	(segment
		(start 78.199996 -238.88954)
		(end 78.801976 -238.88954)
		(width 0.20066)
		(layer "F.Cu")
		(net "M_A_CPU1_SB_DQS_DP<4>")
	)
	(segment
		(start 78.926436 -239.014)
		(end 79.528416 -239.014)
		(width 0.20066)
		(layer "F.Cu")
		(net "M_A_CPU1_SB_DQS_DP<4>")
	)
	(segment
		(start 70.783958 -237.244128)
		(end 71.385938 -237.244128)
		(width 0.20066)
		(layer "F.Cu")
		(net "M_A_CPU1_SB_DQS_DP<4>")
	)
	(segment
		(start 83.32216 -239.39246)
		(end 83.337654 -239.407954)
		(width 0.088646)
		(layer "F.Cu")
		(net "M_A_CPU1_SB_DQS_DP<4>")
	)
	(segment
		(start 64.567562 -236.416596)
		(end 65.047114 -236.416596)
		(width 0.20066)
		(layer "F.Cu")
		(net "M_A_CPU1_SB_DQS_DP<4>")
	)
	(segment
		(start 66.772282 -236.909864)
		(end 66.896742 -236.785404)
		(width 0.20066)
		(layer "F.Cu")
		(net "M_A_CPU1_SB_DQS_DP<4>")
	)
	(segment
		(start 58.903108 -236.34827)
		(end 59.13755 -236.251242)
		(width 0.20066)
		(layer "F.Cu")
		(net "M_A_CPU1_SB_DQS_DP<4>")
	)
	(segment
		(start 75.702922 -238.882936)
		(end 75.833986 -239.014)
		(width 0.20066)
		(layer "F.Cu")
		(net "M_A_CPU1_SB_DQS_DP<4>")
	)
	(segment
		(start 84.11337 -239.824006)
		(end 84.85632 -239.824006)
		(width 0.088646)
		(layer "F.Cu")
		(net "M_A_CPU1_SB_DQS_DP<4>")
	)
	(segment
		(start 66.055748 -236.79531)
		(end 66.170302 -236.909864)
		(width 0.20066)
		(layer "F.Cu")
		(net "M_A_CPU1_SB_DQS_DP<4>")
	)
	(segment
		(start 68.145914 -236.909864)
		(end 68.604638 -237.368588)
		(width 0.20066)
		(layer "F.Cu")
		(net "M_A_CPU1_SB_DQS_DP<4>")
	)
	(segment
		(start 58.239152 -236.677962)
		(end 58.573416 -236.677962)
		(width 0.20066)
		(layer "F.Cu")
		(net "M_A_CPU1_SB_DQS_DP<4>")
	)
	(segment
		(start 86.428326 -240.073688)
		(end 86.546436 -240.304828)
		(width 0.088646)
		(layer "F.Cu")
		(net "M_A_CPU1_SB_DQS_DP<4>")
	)
	(segment
		(start 81.019396 -239.014)
		(end 81.056226 -239.05083)
		(width 0.1524)
		(layer "F.Cu")
		(net "M_A_CPU1_SB_DQS_DP<4>")
	)
	(segment
		(start 66.055748 -236.608874)
		(end 66.055748 -236.79531)
		(width 0.20066)
		(layer "F.Cu")
		(net "M_A_CPU1_SB_DQS_DP<4>")
	)
	(segment
		(start 63.233808 -236.255306)
		(end 63.866268 -236.677962)
		(width 0.20066)
		(layer "F.Cu")
		(net "M_A_CPU1_SB_DQS_DP<4>")
	)
	(segment
		(start 69.331078 -237.244128)
		(end 69.933058 -237.244128)
		(width 0.20066)
		(layer "F.Cu")
		(net "M_A_CPU1_SB_DQS_DP<4>")
	)
	(segment
		(start 72.366886 -237.598712)
		(end 72.529446 -237.531402)
		(width 0.20066)
		(layer "F.Cu")
		(net "M_A_CPU1_SB_DQS_DP<4>")
	)
	(segment
		(start 73.875646 -238.223806)
		(end 74.222864 -238.223806)
		(width 0.20066)
		(layer "F.Cu")
		(net "M_A_CPU1_SB_DQS_DP<4>")
	)
	(segment
		(start 57.503314 -236.416596)
		(end 57.977786 -236.416596)
		(width 0.20066)
		(layer "F.Cu")
		(net "M_A_CPU1_SB_DQS_DP<4>")
	)
	(segment
		(start 82.98053 -239.05083)
		(end 83.32216 -239.39246)
		(width 0.1524)
		(layer "F.Cu")
		(net "M_A_CPU1_SB_DQS_DP<4>")
	)
	(segment
		(start 80.981296 -239.014)
		(end 81.019396 -239.014)
		(width 0.1524)
		(layer "F.Cu")
		(net "M_A_CPU1_SB_DQS_DP<4>")
	)
	(segment
		(start 78.801976 -238.88954)
		(end 78.926436 -239.014)
		(width 0.20066)
		(layer "F.Cu")
		(net "M_A_CPU1_SB_DQS_DP<4>")
	)
	(segment
		(start 65.86347 -236.416596)
		(end 66.055748 -236.608874)
		(width 0.20066)
		(layer "F.Cu")
		(net "M_A_CPU1_SB_DQS_DP<4>")
	)
	(segment
		(start 83.503516 -239.618774)
		(end 83.660488 -239.618774)
		(width 0.088646)
		(layer "F.Cu")
		(net "M_A_CPU1_SB_DQS_DP<4>")
	)
	(segment
		(start 59.13755 -236.251242)
		(end 59.362848 -236.251242)
		(width 0.20066)
		(layer "F.Cu")
		(net "M_A_CPU1_SB_DQS_DP<4>")
	)
	(segment
		(start 71.81088 -237.368588)
		(end 72.366886 -237.598712)
		(width 0.20066)
		(layer "F.Cu")
		(net "M_A_CPU1_SB_DQS_DP<4>")
	)
	(segment
		(start 75.310238 -237.320074)
		(end 75.702922 -237.712758)
		(width 0.20066)
		(layer "F.Cu")
		(net "M_A_CPU1_SB_DQS_DP<4>")
	)
	(segment
		(start 86.630764 -240.389156)
		(end 86.735666 -240.389156)
		(width 0.088646)
		(layer "F.Cu")
		(net "M_A_CPU1_SB_DQS_DP<4>")
	)
	(segment
		(start 86.067392 -239.893348)
		(end 86.428326 -240.073688)
		(width 0.088646)
		(layer "F.Cu")
		(net "M_A_CPU1_SB_DQS_DP<4>")
	)
	(segment
		(start 86.546436 -240.304828)
		(end 86.630764 -240.389156)
		(width 0.088646)
		(layer "F.Cu")
		(net "M_A_CPU1_SB_DQS_DP<4>")
	)
	(segment
		(start 66.896742 -236.785404)
		(end 67.498722 -236.785404)
		(width 0.20066)
		(layer "F.Cu")
		(net "M_A_CPU1_SB_DQS_DP<4>")
	)
	(segment
		(start 75.833986 -239.014)
		(end 76.622656 -239.014)
		(width 0.20066)
		(layer "F.Cu")
		(net "M_A_CPU1_SB_DQS_DP<4>")
	)
	(segment
		(start 74.329544 -238.117126)
		(end 74.329544 -237.712758)
		(width 0.20066)
		(layer "F.Cu")
		(net "M_A_CPU1_SB_DQS_DP<4>")
	)
	(segment
		(start 71.510398 -237.368588)
		(end 71.81088 -237.368588)
		(width 0.20066)
		(layer "F.Cu")
		(net "M_A_CPU1_SB_DQS_DP<4>")
	)
	(segment
		(start 79.652876 -238.88954)
		(end 80.254856 -238.88954)
		(width 0.20066)
		(layer "F.Cu")
		(net "M_A_CPU1_SB_DQS_DP<4>")
	)
	(segment
		(start 62.50559 -235.991654)
		(end 62.769242 -236.255306)
		(width 0.20066)
		(layer "F.Cu")
		(net "M_A_CPU1_SB_DQS_DP<4>")
	)
	(segment
		(start 66.170302 -236.909864)
		(end 66.772282 -236.909864)
		(width 0.20066)
		(layer "F.Cu")
		(net "M_A_CPU1_SB_DQS_DP<4>")
	)
	(segment
		(start 83.660488 -239.618774)
		(end 83.812126 -239.770158)
		(width 0.088646)
		(layer "F.Cu")
		(net "M_A_CPU1_SB_DQS_DP<4>")
	)
	(segment
		(start 63.866268 -236.677962)
		(end 64.306196 -236.677962)
		(width 0.20066)
		(layer "F.Cu")
		(net "M_A_CPU1_SB_DQS_DP<4>")
	)
	(segment
		(start 67.623182 -236.909864)
		(end 68.145914 -236.909864)
		(width 0.20066)
		(layer "F.Cu")
		(net "M_A_CPU1_SB_DQS_DP<4>")
	)
	(segment
		(start 69.933058 -237.244128)
		(end 70.057518 -237.368588)
		(width 0.20066)
		(layer "F.Cu")
		(net "M_A_CPU1_SB_DQS_DP<4>")
	)
	(segment
		(start 80.379316 -239.014)
		(end 80.981296 -239.014)
		(width 0.20066)
		(layer "F.Cu")
		(net "M_A_CPU1_SB_DQS_DP<4>")
	)
	(segment
		(start 59.69889 -235.991654)
		(end 62.404752 -235.991654)
		(width 0.1016)
		(layer "F.Cu")
		(net "M_A_CPU1_SB_DQS_DP<4>")
	)
	(segment
		(start 69.206618 -237.368588)
		(end 69.331078 -237.244128)
		(width 0.20066)
		(layer "F.Cu")
		(net "M_A_CPU1_SB_DQS_DP<4>")
	)
	(segment
		(start 73.15327 -237.924594)
		(end 73.875646 -238.223806)
		(width 0.20066)
		(layer "F.Cu")
		(net "M_A_CPU1_SB_DQS_DP<4>")
	)
	(segment
		(start 76.622656 -239.014)
		(end 76.747116 -238.88954)
		(width 0.20066)
		(layer "F.Cu")
		(net "M_A_CPU1_SB_DQS_DP<4>")
	)
	(segment
		(start 71.385938 -237.244128)
		(end 71.510398 -237.368588)
		(width 0.20066)
		(layer "F.Cu")
		(net "M_A_CPU1_SB_DQS_DP<4>")
	)
	(segment
		(start 65.047114 -236.416596)
		(end 65.86347 -236.416596)
		(width 0.20066)
		(layer "F.Cu")
		(net "M_A_CPU1_SB_DQS_DP<4>")
	)
	(segment
		(start 74.329544 -237.712758)
		(end 74.722228 -237.320074)
		(width 0.20066)
		(layer "F.Cu")
		(net "M_A_CPU1_SB_DQS_DP<4>")
	)
	(segment
		(start 73.08596 -237.762034)
		(end 73.15327 -237.924594)
		(width 0.20066)
		(layer "F.Cu")
		(net "M_A_CPU1_SB_DQS_DP<4>")
	)
	(segment
		(start 77.473556 -239.014)
		(end 78.075536 -239.014)
		(width 0.20066)
		(layer "F.Cu")
		(net "M_A_CPU1_SB_DQS_DP<4>")
	)
	(segment
		(start 62.404752 -235.991654)
		(end 62.50559 -235.991654)
		(width 0.20066)
		(layer "F.Cu")
		(net "M_A_CPU1_SB_DQS_DP<4>")
	)
	(segment
		(start 70.659498 -237.368588)
		(end 70.783958 -237.244128)
		(width 0.20066)
		(layer "F.Cu")
		(net "M_A_CPU1_SB_DQS_DP<4>")
	)
	(segment
		(start 58.573416 -236.677962)
		(end 58.903108 -236.34827)
		(width 0.20066)
		(layer "F.Cu")
		(net "M_A_CPU1_SB_DQS_DP<4>")
	)
	(segment
		(start 64.306196 -236.677962)
		(end 64.567562 -236.416596)
		(width 0.20066)
		(layer "F.Cu")
		(net "M_A_CPU1_SB_DQS_DP<4>")
	)
	(segment
		(start 85.138514 -239.899952)
		(end 85.138514 -239.899698)
		(width 0.088646)
		(layer "F.Cu")
		(net "M_A_CPU1_SB_DQS_DP<4>")
	)
	(segment
		(start 68.604638 -237.368588)
		(end 69.206618 -237.368588)
		(width 0.20066)
		(layer "F.Cu")
		(net "M_A_CPU1_SB_DQS_DP<4>")
	)
	(arc
		(start 84.85632 -239.824006)
		(mid 85.002408 -239.843427)
		(end 85.138514 -239.899952)
		(width 0.088646)
		(layer "F.Cu")
		(net "M_A_CPU1_SB_DQS_DP<4>")
	)
	(arc
		(start 85.51291 -239.899698)
		(mid 85.789014 -239.823712)
		(end 86.066884 -239.89284)
		(width 0.088646)
		(layer "F.Cu")
		(net "M_A_CPU1_SB_DQS_DP<4>")
	)
	(arc
		(start 83.812126 -239.770158)
		(mid 83.960373 -239.810363)
		(end 84.11337 -239.824006)
		(width 0.088646)
		(layer "F.Cu")
		(net "M_A_CPU1_SB_DQS_DP<4>")
	)
	(arc
		(start 85.138514 -239.899698)
		(mid 85.325712 -239.949841)
		(end 85.51291 -239.899698)
		(width 0.088646)
		(layer "F.Cu")
		(net "M_A_CPU1_SB_DQS_DP<4>")
	)
	(segment
		(start 56.37911 -201.148188)
		(end 56.379364 -201.147934)
		(width 0.20066)
		(layer "F.Cu")
		(net "M_A_CPU1_SB_DQS_DP<3>")
	)
	(segment
		(start 83.415378 -219.981272)
		(end 83.370166 -219.981272)
		(width 0.088646)
		(layer "F.Cu")
		(net "M_A_CPU1_SB_DQS_DP<3>")
	)
	(segment
		(start 82.645504 -215.41613)
		(end 83.460336 -214.601298)
		(width 0.1524)
		(layer "F.Cu")
		(net "M_A_CPU1_SB_DQS_DP<3>")
	)
	(segment
		(start 63.486538 -200.935336)
		(end 63.112396 -200.935336)
		(width 0.20066)
		(layer "F.Cu")
		(net "M_A_CPU1_SB_DQS_DP<3>")
	)
	(segment
		(start 58.69432 -201.141838)
		(end 58.70448 -201.151998)
		(width 0.101854)
		(layer "F.Cu")
		(net "M_A_CPU1_SB_DQS_DP<3>")
	)
	(segment
		(start 63.112396 -200.935336)
		(end 61.92901 -200.445116)
		(width 0.20066)
		(layer "F.Cu")
		(net "M_A_CPU1_SB_DQS_DP<3>")
	)
	(segment
		(start 66.212212 -201.148188)
		(end 66.205608 -201.148188)
		(width 0.1016)
		(layer "F.Cu")
		(net "M_A_CPU1_SB_DQS_DP<3>")
	)
	(segment
		(start 56.379364 -201.147934)
		(end 56.38546 -201.141838)
		(width 0.101854)
		(layer "F.Cu")
		(net "M_A_CPU1_SB_DQS_DP<3>")
	)
	(segment
		(start 84.145882 -220.711522)
		(end 84.145628 -220.711522)
		(width 0.088646)
		(layer "F.Cu")
		(net "M_A_CPU1_SB_DQS_DP<3>")
	)
	(segment
		(start 63.487808 -200.934066)
		(end 63.486538 -200.935336)
		(width 0.20066)
		(layer "F.Cu")
		(net "M_A_CPU1_SB_DQS_DP<3>")
	)
	(segment
		(start 84.27085 -220.83649)
		(end 84.145882 -220.711522)
		(width 0.088646)
		(layer "F.Cu")
		(net "M_A_CPU1_SB_DQS_DP<3>")
	)
	(segment
		(start 63.709804 -201.156062)
		(end 63.487808 -200.934066)
		(width 0.20066)
		(layer "F.Cu")
		(net "M_A_CPU1_SB_DQS_DP<3>")
	)
	(segment
		(start 60.11672 -200.434956)
		(end 60.398406 -200.716642)
		(width 0.20066)
		(layer "F.Cu")
		(net "M_A_CPU1_SB_DQS_DP<3>")
	)
	(segment
		(start 64.002412 -201.156062)
		(end 63.709804 -201.156062)
		(width 0.20066)
		(layer "F.Cu")
		(net "M_A_CPU1_SB_DQS_DP<3>")
	)
	(segment
		(start 59.263026 -200.887076)
		(end 59.536076 -200.887076)
		(width 0.20066)
		(layer "F.Cu")
		(net "M_A_CPU1_SB_DQS_DP<3>")
	)
	(segment
		(start 55.992776 -201.148188)
		(end 56.37911 -201.148188)
		(width 0.20066)
		(layer "F.Cu")
		(net "M_A_CPU1_SB_DQS_DP<3>")
	)
	(segment
		(start 53.403246 -200.716642)
		(end 53.992526 -200.716642)
		(width 0.20066)
		(layer "F.Cu")
		(net "M_A_CPU1_SB_DQS_DP<3>")
	)
	(segment
		(start 55.732426 -200.887838)
		(end 55.992776 -201.148188)
		(width 0.20066)
		(layer "F.Cu")
		(net "M_A_CPU1_SB_DQS_DP<3>")
	)
	(segment
		(start 54.416198 -200.465182)
		(end 55.436262 -200.887838)
		(width 0.20066)
		(layer "F.Cu")
		(net "M_A_CPU1_SB_DQS_DP<3>")
	)
	(segment
		(start 58.996834 -201.153268)
		(end 59.263026 -200.887076)
		(width 0.20066)
		(layer "F.Cu")
		(net "M_A_CPU1_SB_DQS_DP<3>")
	)
	(segment
		(start 56.38546 -201.141838)
		(end 58.69432 -201.141838)
		(width 0.1016)
		(layer "F.Cu")
		(net "M_A_CPU1_SB_DQS_DP<3>")
	)
	(segment
		(start 66.199004 -201.141584)
		(end 64.01689 -201.141584)
		(width 0.1016)
		(layer "F.Cu")
		(net "M_A_CPU1_SB_DQS_DP<3>")
	)
	(segment
		(start 83.399122 -210.306158)
		(end 73.99274 -200.899776)
		(width 0.20066)
		(layer "F.Cu")
		(net "M_A_CPU1_SB_DQS_DP<3>")
	)
	(segment
		(start 61.712856 -200.445116)
		(end 61.44133 -200.716642)
		(width 0.20066)
		(layer "F.Cu")
		(net "M_A_CPU1_SB_DQS_DP<3>")
	)
	(segment
		(start 61.44133 -200.716642)
		(end 60.947046 -200.716642)
		(width 0.20066)
		(layer "F.Cu")
		(net "M_A_CPU1_SB_DQS_DP<3>")
	)
	(segment
		(start 60.398406 -200.716642)
		(end 60.947046 -200.716642)
		(width 0.20066)
		(layer "F.Cu")
		(net "M_A_CPU1_SB_DQS_DP<3>")
	)
	(segment
		(start 66.609468 -200.899776)
		(end 66.361056 -201.148188)
		(width 0.20066)
		(layer "F.Cu")
		(net "M_A_CPU1_SB_DQS_DP<3>")
	)
	(segment
		(start 84.525358 -221.149926)
		(end 84.312252 -220.93682)
		(width 0.088646)
		(layer "F.Cu")
		(net "M_A_CPU1_SB_DQS_DP<3>")
	)
	(segment
		(start 82.645504 -219.25661)
		(end 82.645504 -215.41613)
		(width 0.1524)
		(layer "F.Cu")
		(net "M_A_CPU1_SB_DQS_DP<3>")
	)
	(segment
		(start 54.243986 -200.465182)
		(end 54.416198 -200.465182)
		(width 0.20066)
		(layer "F.Cu")
		(net "M_A_CPU1_SB_DQS_DP<3>")
	)
	(segment
		(start 83.370166 -219.981272)
		(end 83.354672 -219.965778)
		(width 0.088646)
		(layer "F.Cu")
		(net "M_A_CPU1_SB_DQS_DP<3>")
	)
	(segment
		(start 73.99274 -200.899776)
		(end 66.609468 -200.899776)
		(width 0.20066)
		(layer "F.Cu")
		(net "M_A_CPU1_SB_DQS_DP<3>")
	)
	(segment
		(start 83.432396 -214.033608)
		(end 83.432396 -210.386422)
		(width 0.20066)
		(layer "F.Cu")
		(net "M_A_CPU1_SB_DQS_DP<3>")
	)
	(segment
		(start 59.536076 -200.887076)
		(end 59.988196 -200.434956)
		(width 0.20066)
		(layer "F.Cu")
		(net "M_A_CPU1_SB_DQS_DP<3>")
	)
	(segment
		(start 66.361056 -201.148188)
		(end 66.212212 -201.148188)
		(width 0.20066)
		(layer "F.Cu")
		(net "M_A_CPU1_SB_DQS_DP<3>")
	)
	(segment
		(start 64.01689 -201.141584)
		(end 64.002412 -201.156062)
		(width 0.1016)
		(layer "F.Cu")
		(net "M_A_CPU1_SB_DQS_DP<3>")
	)
	(segment
		(start 84.94522 -221.193106)
		(end 84.630006 -221.193106)
		(width 0.088646)
		(layer "F.Cu")
		(net "M_A_CPU1_SB_DQS_DP<3>")
	)
	(segment
		(start 84.312252 -220.93682)
		(end 84.27085 -220.83649)
		(width 0.088646)
		(layer "F.Cu")
		(net "M_A_CPU1_SB_DQS_DP<3>")
	)
	(segment
		(start 84.630006 -221.193106)
		(end 84.525358 -221.149926)
		(width 0.088646)
		(layer "F.Cu")
		(net "M_A_CPU1_SB_DQS_DP<3>")
	)
	(segment
		(start 59.988196 -200.434956)
		(end 60.11672 -200.434956)
		(width 0.20066)
		(layer "F.Cu")
		(net "M_A_CPU1_SB_DQS_DP<3>")
	)
	(segment
		(start 58.70448 -201.151998)
		(end 58.70575 -201.153268)
		(width 0.20066)
		(layer "F.Cu")
		(net "M_A_CPU1_SB_DQS_DP<3>")
	)
	(segment
		(start 84.145628 -220.711522)
		(end 83.415378 -219.981272)
		(width 0.088646)
		(layer "F.Cu")
		(net "M_A_CPU1_SB_DQS_DP<3>")
	)
	(segment
		(start 53.992526 -200.716642)
		(end 54.243986 -200.465182)
		(width 0.20066)
		(layer "F.Cu")
		(net "M_A_CPU1_SB_DQS_DP<3>")
	)
	(segment
		(start 58.70575 -201.153268)
		(end 58.996834 -201.153268)
		(width 0.20066)
		(layer "F.Cu")
		(net "M_A_CPU1_SB_DQS_DP<3>")
	)
	(segment
		(start 84.997036 -221.16288)
		(end 84.94522 -221.193106)
		(width 0.088646)
		(layer "F.Cu")
		(net "M_A_CPU1_SB_DQS_DP<3>")
	)
	(segment
		(start 83.432396 -210.386422)
		(end 83.399122 -210.306158)
		(width 0.20066)
		(layer "F.Cu")
		(net "M_A_CPU1_SB_DQS_DP<3>")
	)
	(segment
		(start 83.460336 -214.601298)
		(end 83.460336 -214.061548)
		(width 0.1524)
		(layer "F.Cu")
		(net "M_A_CPU1_SB_DQS_DP<3>")
	)
	(segment
		(start 55.436262 -200.887838)
		(end 55.732426 -200.887838)
		(width 0.20066)
		(layer "F.Cu")
		(net "M_A_CPU1_SB_DQS_DP<3>")
	)
	(segment
		(start 61.92901 -200.445116)
		(end 61.712856 -200.445116)
		(width 0.20066)
		(layer "F.Cu")
		(net "M_A_CPU1_SB_DQS_DP<3>")
	)
	(segment
		(start 66.205608 -201.148188)
		(end 66.199004 -201.141584)
		(width 0.1016)
		(layer "F.Cu")
		(net "M_A_CPU1_SB_DQS_DP<3>")
	)
	(segment
		(start 85.75675 -220.840046)
		(end 84.997036 -221.16288)
		(width 0.088646)
		(layer "F.Cu")
		(net "M_A_CPU1_SB_DQS_DP<3>")
	)
	(segment
		(start 85.795866 -220.855794)
		(end 85.75675 -220.840046)
		(width 0.088646)
		(layer "F.Cu")
		(net "M_A_CPU1_SB_DQS_DP<3>")
	)
	(segment
		(start 83.460336 -214.061548)
		(end 83.432396 -214.033608)
		(width 0.1524)
		(layer "F.Cu")
		(net "M_A_CPU1_SB_DQS_DP<3>")
	)
	(segment
		(start 83.354672 -219.965778)
		(end 82.645504 -219.25661)
		(width 0.1524)
		(layer "F.Cu")
		(net "M_A_CPU1_SB_DQS_DP<3>")
	)
	(segment
		(start 59.263026 -210.23707)
		(end 59.536076 -210.23707)
		(width 0.20066)
		(layer "F.Cu")
		(net "M_A_CPU1_SB_DQS_DP<2>")
	)
	(segment
		(start 56.379364 -210.497928)
		(end 56.38546 -210.491832)
		(width 0.101854)
		(layer "F.Cu")
		(net "M_A_CPU1_SB_DQS_DP<2>")
	)
	(segment
		(start 66.147188 -210.491578)
		(end 64.055498 -210.491578)
		(width 0.1016)
		(layer "F.Cu")
		(net "M_A_CPU1_SB_DQS_DP<2>")
	)
	(segment
		(start 59.536076 -210.23707)
		(end 59.988196 -209.78495)
		(width 0.20066)
		(layer "F.Cu")
		(net "M_A_CPU1_SB_DQS_DP<2>")
	)
	(segment
		(start 58.69432 -210.491832)
		(end 58.70448 -210.501992)
		(width 0.101854)
		(layer "F.Cu")
		(net "M_A_CPU1_SB_DQS_DP<2>")
	)
	(segment
		(start 83.954112 -230.926132)
		(end 83.932014 -230.926132)
		(width 0.088646)
		(layer "F.Cu")
		(net "M_A_CPU1_SB_DQS_DP<2>")
	)
	(segment
		(start 61.851032 -209.821272)
		(end 61.686694 -209.821272)
		(width 0.20066)
		(layer "F.Cu")
		(net "M_A_CPU1_SB_DQS_DP<2>")
	)
	(segment
		(start 77.434694 -216.436448)
		(end 71.213218 -210.214972)
		(width 0.20066)
		(layer "F.Cu")
		(net "M_A_CPU1_SB_DQS_DP<2>")
	)
	(segment
		(start 66.167 -210.51139)
		(end 66.147188 -210.491578)
		(width 0.1016)
		(layer "F.Cu")
		(net "M_A_CPU1_SB_DQS_DP<2>")
	)
	(segment
		(start 63.269114 -210.239864)
		(end 62.861698 -210.239864)
		(width 0.20066)
		(layer "F.Cu")
		(net "M_A_CPU1_SB_DQS_DP<2>")
	)
	(segment
		(start 64.055498 -210.491578)
		(end 63.977012 -210.500722)
		(width 0.1016)
		(layer "F.Cu")
		(net "M_A_CPU1_SB_DQS_DP<2>")
	)
	(segment
		(start 79.582264 -224.971356)
		(end 77.976984 -223.366076)
		(width 0.1524)
		(layer "F.Cu")
		(net "M_A_CPU1_SB_DQS_DP<2>")
	)
	(segment
		(start 54.416198 -209.815176)
		(end 55.436262 -210.237832)
		(width 0.20066)
		(layer "F.Cu")
		(net "M_A_CPU1_SB_DQS_DP<2>")
	)
	(segment
		(start 53.992526 -210.066636)
		(end 54.243986 -209.815176)
		(width 0.20066)
		(layer "F.Cu")
		(net "M_A_CPU1_SB_DQS_DP<2>")
	)
	(segment
		(start 84.978748 -230.97998)
		(end 84.76742 -230.981504)
		(width 0.088646)
		(layer "F.Cu")
		(net "M_A_CPU1_SB_DQS_DP<2>")
	)
	(segment
		(start 55.992776 -210.498182)
		(end 56.37911 -210.498182)
		(width 0.20066)
		(layer "F.Cu")
		(net "M_A_CPU1_SB_DQS_DP<2>")
	)
	(segment
		(start 84.76742 -230.981504)
		(end 84.297774 -230.981504)
		(width 0.088646)
		(layer "F.Cu")
		(net "M_A_CPU1_SB_DQS_DP<2>")
	)
	(segment
		(start 53.403246 -210.066636)
		(end 53.992526 -210.066636)
		(width 0.20066)
		(layer "F.Cu")
		(net "M_A_CPU1_SB_DQS_DP<2>")
	)
	(segment
		(start 77.512926 -216.463118)
		(end 77.461618 -216.463372)
		(width 0.1524)
		(layer "F.Cu")
		(net "M_A_CPU1_SB_DQS_DP<2>")
	)
	(segment
		(start 61.686694 -209.821272)
		(end 61.44133 -210.066636)
		(width 0.20066)
		(layer "F.Cu")
		(net "M_A_CPU1_SB_DQS_DP<2>")
	)
	(segment
		(start 77.976984 -223.366076)
		(end 77.976984 -217.2335)
		(width 0.1524)
		(layer "F.Cu")
		(net "M_A_CPU1_SB_DQS_DP<2>")
	)
	(segment
		(start 63.977012 -210.500722)
		(end 63.529972 -210.500722)
		(width 0.20066)
		(layer "F.Cu")
		(net "M_A_CPU1_SB_DQS_DP<2>")
	)
	(segment
		(start 66.559176 -210.51139)
		(end 66.186812 -210.51139)
		(width 0.20066)
		(layer "F.Cu")
		(net "M_A_CPU1_SB_DQS_DP<2>")
	)
	(segment
		(start 58.70575 -210.503262)
		(end 58.996834 -210.503262)
		(width 0.20066)
		(layer "F.Cu")
		(net "M_A_CPU1_SB_DQS_DP<2>")
	)
	(segment
		(start 59.988196 -209.78495)
		(end 60.11672 -209.78495)
		(width 0.20066)
		(layer "F.Cu")
		(net "M_A_CPU1_SB_DQS_DP<2>")
	)
	(segment
		(start 85.795866 -230.622602)
		(end 85.093048 -230.91394)
		(width 0.088646)
		(layer "F.Cu")
		(net "M_A_CPU1_SB_DQS_DP<2>")
	)
	(segment
		(start 58.996834 -210.503262)
		(end 59.263026 -210.23707)
		(width 0.20066)
		(layer "F.Cu")
		(net "M_A_CPU1_SB_DQS_DP<2>")
	)
	(segment
		(start 55.732426 -210.237832)
		(end 55.992776 -210.498182)
		(width 0.20066)
		(layer "F.Cu")
		(net "M_A_CPU1_SB_DQS_DP<2>")
	)
	(segment
		(start 83.397598 -230.926132)
		(end 79.582264 -227.110798)
		(width 0.1524)
		(layer "F.Cu")
		(net "M_A_CPU1_SB_DQS_DP<2>")
	)
	(segment
		(start 71.213218 -210.214972)
		(end 66.855594 -210.214972)
		(width 0.20066)
		(layer "F.Cu")
		(net "M_A_CPU1_SB_DQS_DP<2>")
	)
	(segment
		(start 66.855594 -210.214972)
		(end 66.559176 -210.51139)
		(width 0.20066)
		(layer "F.Cu")
		(net "M_A_CPU1_SB_DQS_DP<2>")
	)
	(segment
		(start 60.11672 -209.78495)
		(end 60.398406 -210.066636)
		(width 0.20066)
		(layer "F.Cu")
		(net "M_A_CPU1_SB_DQS_DP<2>")
	)
	(segment
		(start 58.70448 -210.501992)
		(end 58.70575 -210.503262)
		(width 0.20066)
		(layer "F.Cu")
		(net "M_A_CPU1_SB_DQS_DP<2>")
	)
	(segment
		(start 85.093048 -230.91394)
		(end 84.978748 -230.97998)
		(width 0.088646)
		(layer "F.Cu")
		(net "M_A_CPU1_SB_DQS_DP<2>")
	)
	(segment
		(start 62.861698 -210.239864)
		(end 61.851032 -209.821272)
		(width 0.20066)
		(layer "F.Cu")
		(net "M_A_CPU1_SB_DQS_DP<2>")
	)
	(segment
		(start 54.243986 -209.815176)
		(end 54.416198 -209.815176)
		(width 0.20066)
		(layer "F.Cu")
		(net "M_A_CPU1_SB_DQS_DP<2>")
	)
	(segment
		(start 83.985862 -230.894382)
		(end 83.954112 -230.926132)
		(width 0.088646)
		(layer "F.Cu")
		(net "M_A_CPU1_SB_DQS_DP<2>")
	)
	(segment
		(start 55.436262 -210.237832)
		(end 55.732426 -210.237832)
		(width 0.20066)
		(layer "F.Cu")
		(net "M_A_CPU1_SB_DQS_DP<2>")
	)
	(segment
		(start 84.297774 -230.981504)
		(end 84.210652 -230.894382)
		(width 0.088646)
		(layer "F.Cu")
		(net "M_A_CPU1_SB_DQS_DP<2>")
	)
	(segment
		(start 66.186812 -210.51139)
		(end 66.167 -210.51139)
		(width 0.1016)
		(layer "F.Cu")
		(net "M_A_CPU1_SB_DQS_DP<2>")
	)
	(segment
		(start 61.44133 -210.066636)
		(end 60.947046 -210.066636)
		(width 0.20066)
		(layer "F.Cu")
		(net "M_A_CPU1_SB_DQS_DP<2>")
	)
	(segment
		(start 77.461618 -216.463372)
		(end 77.434694 -216.436448)
		(width 0.1524)
		(layer "F.Cu")
		(net "M_A_CPU1_SB_DQS_DP<2>")
	)
	(segment
		(start 60.398406 -210.066636)
		(end 60.947046 -210.066636)
		(width 0.20066)
		(layer "F.Cu")
		(net "M_A_CPU1_SB_DQS_DP<2>")
	)
	(segment
		(start 56.37911 -210.498182)
		(end 56.379364 -210.497928)
		(width 0.20066)
		(layer "F.Cu")
		(net "M_A_CPU1_SB_DQS_DP<2>")
	)
	(segment
		(start 77.760322 -216.710514)
		(end 77.512926 -216.463118)
		(width 0.1524)
		(layer "F.Cu")
		(net "M_A_CPU1_SB_DQS_DP<2>")
	)
	(segment
		(start 79.582264 -227.110798)
		(end 79.582264 -224.971356)
		(width 0.1524)
		(layer "F.Cu")
		(net "M_A_CPU1_SB_DQS_DP<2>")
	)
	(segment
		(start 83.932014 -230.926132)
		(end 83.397598 -230.926132)
		(width 0.1524)
		(layer "F.Cu")
		(net "M_A_CPU1_SB_DQS_DP<2>")
	)
	(segment
		(start 77.976984 -217.2335)
		(end 77.760322 -216.710514)
		(width 0.1524)
		(layer "F.Cu")
		(net "M_A_CPU1_SB_DQS_DP<2>")
	)
	(segment
		(start 84.210652 -230.894382)
		(end 83.985862 -230.894382)
		(width 0.088646)
		(layer "F.Cu")
		(net "M_A_CPU1_SB_DQS_DP<2>")
	)
	(segment
		(start 56.38546 -210.491832)
		(end 58.69432 -210.491832)
		(width 0.1016)
		(layer "F.Cu")
		(net "M_A_CPU1_SB_DQS_DP<2>")
	)
	(segment
		(start 63.529972 -210.500722)
		(end 63.269114 -210.239864)
		(width 0.20066)
		(layer "F.Cu")
		(net "M_A_CPU1_SB_DQS_DP<2>")
	)
	(segment
		(start 62.924436 -219.590366)
		(end 61.89853 -219.165424)
		(width 0.20066)
		(layer "F.Cu")
		(net "M_A_CPU1_SB_DQS_DP<1>")
	)
	(segment
		(start 53.403246 -219.41663)
		(end 53.992526 -219.41663)
		(width 0.20066)
		(layer "F.Cu")
		(net "M_A_CPU1_SB_DQS_DP<1>")
	)
	(segment
		(start 83.932522 -235.683044)
		(end 83.524598 -235.683044)
		(width 0.088646)
		(layer "F.Cu")
		(net "M_A_CPU1_SB_DQS_DP<1>")
	)
	(segment
		(start 84.117434 -235.867956)
		(end 83.932522 -235.683044)
		(width 0.088646)
		(layer "F.Cu")
		(net "M_A_CPU1_SB_DQS_DP<1>")
	)
	(segment
		(start 66.54419 -219.849192)
		(end 66.248026 -219.849192)
		(width 0.20066)
		(layer "F.Cu")
		(net "M_A_CPU1_SB_DQS_DP<1>")
	)
	(segment
		(start 59.536076 -219.587064)
		(end 59.988196 -219.134944)
		(width 0.20066)
		(layer "F.Cu")
		(net "M_A_CPU1_SB_DQS_DP<1>")
	)
	(segment
		(start 63.926212 -219.847922)
		(end 63.49873 -219.847922)
		(width 0.20066)
		(layer "F.Cu")
		(net "M_A_CPU1_SB_DQS_DP<1>")
	)
	(segment
		(start 58.998358 -219.851732)
		(end 59.263026 -219.587064)
		(width 0.20066)
		(layer "F.Cu")
		(net "M_A_CPU1_SB_DQS_DP<1>")
	)
	(segment
		(start 63.49873 -219.847922)
		(end 63.241174 -219.590366)
		(width 0.20066)
		(layer "F.Cu")
		(net "M_A_CPU1_SB_DQS_DP<1>")
	)
	(segment
		(start 67.161918 -219.580714)
		(end 66.812668 -219.580714)
		(width 0.20066)
		(layer "F.Cu")
		(net "M_A_CPU1_SB_DQS_DP<1>")
	)
	(segment
		(start 84.908644 -235.867956)
		(end 84.117434 -235.867956)
		(width 0.088646)
		(layer "F.Cu")
		(net "M_A_CPU1_SB_DQS_DP<1>")
	)
	(segment
		(start 76.701396 -230.006906)
		(end 76.410058 -230.006906)
		(width 0.1524)
		(layer "F.Cu")
		(net "M_A_CPU1_SB_DQS_DP<1>")
	)
	(segment
		(start 82.593942 -235.715048)
		(end 77.016356 -230.137716)
		(width 0.1524)
		(layer "F.Cu")
		(net "M_A_CPU1_SB_DQS_DP<1>")
	)
	(segment
		(start 83.470496 -235.715048)
		(end 82.593942 -235.715048)
		(width 0.1524)
		(layer "F.Cu")
		(net "M_A_CPU1_SB_DQS_DP<1>")
	)
	(segment
		(start 56.38546 -219.841826)
		(end 58.69432 -219.841826)
		(width 0.1016)
		(layer "F.Cu")
		(net "M_A_CPU1_SB_DQS_DP<1>")
	)
	(segment
		(start 83.492594 -235.715048)
		(end 83.470496 -235.715048)
		(width 0.088646)
		(layer "F.Cu")
		(net "M_A_CPU1_SB_DQS_DP<1>")
	)
	(segment
		(start 70.116954 -222.53575)
		(end 67.161918 -219.580714)
		(width 0.20066)
		(layer "F.Cu")
		(net "M_A_CPU1_SB_DQS_DP<1>")
	)
	(segment
		(start 72.535796 -230.04526)
		(end 70.116954 -227.626418)
		(width 0.20066)
		(layer "F.Cu")
		(net "M_A_CPU1_SB_DQS_DP<1>")
	)
	(segment
		(start 66.812668 -219.580714)
		(end 66.54419 -219.849192)
		(width 0.20066)
		(layer "F.Cu")
		(net "M_A_CPU1_SB_DQS_DP<1>")
	)
	(segment
		(start 76.272898 -230.04526)
		(end 76.234798 -230.04526)
		(width 0.1524)
		(layer "F.Cu")
		(net "M_A_CPU1_SB_DQS_DP<1>")
	)
	(segment
		(start 76.308966 -230.008176)
		(end 76.272898 -230.04526)
		(width 0.1524)
		(layer "F.Cu")
		(net "M_A_CPU1_SB_DQS_DP<1>")
	)
	(segment
		(start 58.69432 -219.841826)
		(end 58.704226 -219.851732)
		(width 0.1016)
		(layer "F.Cu")
		(net "M_A_CPU1_SB_DQS_DP<1>")
	)
	(segment
		(start 54.416198 -219.16517)
		(end 55.436262 -219.587826)
		(width 0.20066)
		(layer "F.Cu")
		(net "M_A_CPU1_SB_DQS_DP<1>")
	)
	(segment
		(start 55.992776 -219.848176)
		(end 56.37911 -219.848176)
		(width 0.20066)
		(layer "F.Cu")
		(net "M_A_CPU1_SB_DQS_DP<1>")
	)
	(segment
		(start 85.43417 -235.603034)
		(end 85.036152 -235.833666)
		(width 0.088646)
		(layer "F.Cu")
		(net "M_A_CPU1_SB_DQS_DP<1>")
	)
	(segment
		(start 58.704226 -219.851732)
		(end 58.998358 -219.851732)
		(width 0.20066)
		(layer "F.Cu")
		(net "M_A_CPU1_SB_DQS_DP<1>")
	)
	(segment
		(start 61.44133 -219.41663)
		(end 60.947046 -219.41663)
		(width 0.20066)
		(layer "F.Cu")
		(net "M_A_CPU1_SB_DQS_DP<1>")
	)
	(segment
		(start 66.240406 -219.841572)
		(end 63.932562 -219.841572)
		(width 0.1016)
		(layer "F.Cu")
		(net "M_A_CPU1_SB_DQS_DP<1>")
	)
	(segment
		(start 54.243986 -219.16517)
		(end 54.416198 -219.16517)
		(width 0.20066)
		(layer "F.Cu")
		(net "M_A_CPU1_SB_DQS_DP<1>")
	)
	(segment
		(start 76.410058 -230.006906)
		(end 76.308966 -230.008176)
		(width 0.1524)
		(layer "F.Cu")
		(net "M_A_CPU1_SB_DQS_DP<1>")
	)
	(segment
		(start 60.398406 -219.41663)
		(end 60.947046 -219.41663)
		(width 0.20066)
		(layer "F.Cu")
		(net "M_A_CPU1_SB_DQS_DP<1>")
	)
	(segment
		(start 55.732426 -219.587826)
		(end 55.992776 -219.848176)
		(width 0.20066)
		(layer "F.Cu")
		(net "M_A_CPU1_SB_DQS_DP<1>")
	)
	(segment
		(start 66.248026 -219.849192)
		(end 66.240406 -219.841572)
		(width 0.1016)
		(layer "F.Cu")
		(net "M_A_CPU1_SB_DQS_DP<1>")
	)
	(segment
		(start 56.37911 -219.848176)
		(end 56.38546 -219.841826)
		(width 0.1016)
		(layer "F.Cu")
		(net "M_A_CPU1_SB_DQS_DP<1>")
	)
	(segment
		(start 59.988196 -219.134944)
		(end 60.11672 -219.134944)
		(width 0.20066)
		(layer "F.Cu")
		(net "M_A_CPU1_SB_DQS_DP<1>")
	)
	(segment
		(start 76.234798 -230.04526)
		(end 72.535796 -230.04526)
		(width 0.20066)
		(layer "F.Cu")
		(net "M_A_CPU1_SB_DQS_DP<1>")
	)
	(segment
		(start 61.692536 -219.165424)
		(end 61.44133 -219.41663)
		(width 0.20066)
		(layer "F.Cu")
		(net "M_A_CPU1_SB_DQS_DP<1>")
	)
	(segment
		(start 63.241174 -219.590366)
		(end 62.924436 -219.590366)
		(width 0.20066)
		(layer "F.Cu")
		(net "M_A_CPU1_SB_DQS_DP<1>")
	)
	(segment
		(start 70.116954 -227.626418)
		(end 70.116954 -222.53575)
		(width 0.20066)
		(layer "F.Cu")
		(net "M_A_CPU1_SB_DQS_DP<1>")
	)
	(segment
		(start 85.795866 -235.506006)
		(end 85.43417 -235.603034)
		(width 0.088646)
		(layer "F.Cu")
		(net "M_A_CPU1_SB_DQS_DP<1>")
	)
	(segment
		(start 83.524598 -235.683044)
		(end 83.492594 -235.715048)
		(width 0.088646)
		(layer "F.Cu")
		(net "M_A_CPU1_SB_DQS_DP<1>")
	)
	(segment
		(start 61.89853 -219.165424)
		(end 61.692536 -219.165424)
		(width 0.20066)
		(layer "F.Cu")
		(net "M_A_CPU1_SB_DQS_DP<1>")
	)
	(segment
		(start 53.992526 -219.41663)
		(end 54.243986 -219.16517)
		(width 0.20066)
		(layer "F.Cu")
		(net "M_A_CPU1_SB_DQS_DP<1>")
	)
	(segment
		(start 77.016356 -230.137716)
		(end 76.701396 -230.006906)
		(width 0.1524)
		(layer "F.Cu")
		(net "M_A_CPU1_SB_DQS_DP<1>")
	)
	(segment
		(start 60.11672 -219.134944)
		(end 60.398406 -219.41663)
		(width 0.20066)
		(layer "F.Cu")
		(net "M_A_CPU1_SB_DQS_DP<1>")
	)
	(segment
		(start 63.932562 -219.841572)
		(end 63.926212 -219.847922)
		(width 0.1016)
		(layer "F.Cu")
		(net "M_A_CPU1_SB_DQS_DP<1>")
	)
	(segment
		(start 59.263026 -219.587064)
		(end 59.536076 -219.587064)
		(width 0.20066)
		(layer "F.Cu")
		(net "M_A_CPU1_SB_DQS_DP<1>")
	)
	(segment
		(start 55.436262 -219.587826)
		(end 55.732426 -219.587826)
		(width 0.20066)
		(layer "F.Cu")
		(net "M_A_CPU1_SB_DQS_DP<1>")
	)
	(arc
		(start 85.036152 -235.833666)
		(mid 84.974671 -235.859281)
		(end 84.908644 -235.867956)
		(width 0.088646)
		(layer "F.Cu")
		(net "M_A_CPU1_SB_DQS_DP<1>")
	)
	(segment
		(start 54.533546 -228.515164)
		(end 54.243986 -228.515164)
		(width 0.20066)
		(layer "F.Cu")
		(net "M_A_CPU1_SB_DQS_DP<0>")
	)
	(segment
		(start 55.5752 -228.94671)
		(end 54.533546 -228.515164)
		(width 0.20066)
		(layer "F.Cu")
		(net "M_A_CPU1_SB_DQS_DP<0>")
	)
	(segment
		(start 56.37911 -229.20579)
		(end 56.165496 -229.20579)
		(width 0.20066)
		(layer "F.Cu")
		(net "M_A_CPU1_SB_DQS_DP<0>")
	)
	(segment
		(start 56.39308 -229.19182)
		(end 56.37911 -229.20579)
		(width 0.101854)
		(layer "F.Cu")
		(net "M_A_CPU1_SB_DQS_DP<0>")
	)
	(segment
		(start 62.051946 -228.766624)
		(end 60.947046 -228.766624)
		(width 0.20066)
		(layer "F.Cu")
		(net "M_A_CPU1_SB_DQS_DP<0>")
	)
	(segment
		(start 60.11672 -228.484938)
		(end 59.889136 -228.484938)
		(width 0.20066)
		(layer "F.Cu")
		(net "M_A_CPU1_SB_DQS_DP<0>")
	)
	(segment
		(start 89.084912 -237.947454)
		(end 89.084912 -237.411768)
		(width 0.20066)
		(layer "F.Cu")
		(net "M_A_CPU1_SB_DQS_DP<0>")
	)
	(segment
		(start 53.992526 -228.766624)
		(end 53.403246 -228.766624)
		(width 0.20066)
		(layer "F.Cu")
		(net "M_A_CPU1_SB_DQS_DP<0>")
	)
	(segment
		(start 59.106562 -228.937058)
		(end 58.8518 -229.19182)
		(width 0.20066)
		(layer "F.Cu")
		(net "M_A_CPU1_SB_DQS_DP<0>")
	)
	(segment
		(start 56.165496 -229.20579)
		(end 55.906416 -228.94671)
		(width 0.20066)
		(layer "F.Cu")
		(net "M_A_CPU1_SB_DQS_DP<0>")
	)
	(segment
		(start 58.8518 -229.19182)
		(end 58.704226 -229.19182)
		(width 0.20066)
		(layer "F.Cu")
		(net "M_A_CPU1_SB_DQS_DP<0>")
	)
	(segment
		(start 59.889136 -228.484938)
		(end 59.437016 -228.937058)
		(width 0.20066)
		(layer "F.Cu")
		(net "M_A_CPU1_SB_DQS_DP<0>")
	)
	(segment
		(start 54.243986 -228.515164)
		(end 53.992526 -228.766624)
		(width 0.20066)
		(layer "F.Cu")
		(net "M_A_CPU1_SB_DQS_DP<0>")
	)
	(segment
		(start 55.906416 -228.94671)
		(end 55.5752 -228.94671)
		(width 0.20066)
		(layer "F.Cu")
		(net "M_A_CPU1_SB_DQS_DP<0>")
	)
	(segment
		(start 89.084912 -237.411768)
		(end 89.085166 -237.411514)
		(width 0.20066)
		(layer "F.Cu")
		(net "M_A_CPU1_SB_DQS_DP<0>")
	)
	(segment
		(start 60.947046 -228.766624)
		(end 60.398406 -228.766624)
		(width 0.20066)
		(layer "F.Cu")
		(net "M_A_CPU1_SB_DQS_DP<0>")
	)
	(segment
		(start 59.437016 -228.937058)
		(end 59.106562 -228.937058)
		(width 0.20066)
		(layer "F.Cu")
		(net "M_A_CPU1_SB_DQS_DP<0>")
	)
	(segment
		(start 58.704226 -229.19182)
		(end 58.380884 -229.19182)
		(width 0.101854)
		(layer "F.Cu")
		(net "M_A_CPU1_SB_DQS_DP<0>")
	)
	(segment
		(start 60.398406 -228.766624)
		(end 60.11672 -228.484938)
		(width 0.20066)
		(layer "F.Cu")
		(net "M_A_CPU1_SB_DQS_DP<0>")
	)
	(segment
		(start 56.62549 -229.19182)
		(end 56.39308 -229.19182)
		(width 0.101854)
		(layer "F.Cu")
		(net "M_A_CPU1_SB_DQS_DP<0>")
	)
	(segment
		(start 58.380884 -229.19182)
		(end 56.62549 -229.19182)
		(width 0.1016)
		(layer "F.Cu")
		(net "M_A_CPU1_SB_DQS_DP<0>")
	)
	(segment
		(start 82.759296 -237.89386)
		(end 79.48803 -237.89386)
		(width 0.18288)
		(layer "In2.Cu")
		(net "M_A_CPU1_SB_DQS_DP<0>")
	)
	(segment
		(start 88.115394 -237.785148)
		(end 88.114886 -237.785656)
		(width 0.088646)
		(layer "In2.Cu")
		(net "M_A_CPU1_SB_DQS_DP<0>")
	)
	(segment
		(start 63.803784 -228.241098)
		(end 63.350648 -228.241098)
		(width 0.18288)
		(layer "In2.Cu")
		(net "M_A_CPU1_SB_DQS_DP<0>")
	)
	(segment
		(start 65.665604 -228.896418)
		(end 64.459104 -228.896418)
		(width 0.18288)
		(layer "In2.Cu")
		(net "M_A_CPU1_SB_DQS_DP<0>")
	)
	(segment
		(start 65.961006 -229.19182)
		(end 65.665604 -228.896418)
		(width 0.18288)
		(layer "In2.Cu")
		(net "M_A_CPU1_SB_DQS_DP<0>")
	)
	(segment
		(start 64.226694 -228.664008)
		(end 64.1985 -228.635814)
		(width 0.16002)
		(layer "In2.Cu")
		(net "M_A_CPU1_SB_DQS_DP<0>")
	)
	(segment
		(start 82.818986 -237.83417)
		(end 82.759296 -237.89386)
		(width 0.088646)
		(layer "In2.Cu")
		(net "M_A_CPU1_SB_DQS_DP<0>")
	)
	(segment
		(start 86.923118 -237.900972)
		(end 86.922864 -237.901226)
		(width 0.088646)
		(layer "In2.Cu")
		(net "M_A_CPU1_SB_DQS_DP<0>")
	)
	(segment
		(start 83.854036 -237.83417)
		(end 82.818986 -237.83417)
		(width 0.088646)
		(layer "In2.Cu")
		(net "M_A_CPU1_SB_DQS_DP<0>")
	)
	(segment
		(start 63.998348 -228.419914)
		(end 63.9826 -228.419914)
		(width 0.16002)
		(layer "In2.Cu")
		(net "M_A_CPU1_SB_DQS_DP<0>")
	)
	(segment
		(start 64.1985 -228.635814)
		(end 64.1985 -228.620066)
		(width 0.16002)
		(layer "In2.Cu")
		(net "M_A_CPU1_SB_DQS_DP<0>")
	)
	(segment
		(start 88.114886 -237.785656)
		(end 87.917528 -237.785656)
		(width 0.088646)
		(layer "In2.Cu")
		(net "M_A_CPU1_SB_DQS_DP<0>")
	)
	(segment
		(start 89.085166 -237.411514)
		(end 88.707214 -237.411768)
		(width 0.088646)
		(layer "In2.Cu")
		(net "M_A_CPU1_SB_DQS_DP<0>")
	)
	(segment
		(start 79.48803 -237.89386)
		(end 70.510146 -228.915976)
		(width 0.18288)
		(layer "In2.Cu")
		(net "M_A_CPU1_SB_DQS_DP<0>")
	)
	(segment
		(start 63.350648 -228.241098)
		(end 62.733428 -228.496622)
		(width 0.18288)
		(layer "In2.Cu")
		(net "M_A_CPU1_SB_DQS_DP<0>")
	)
	(segment
		(start 66.33972 -229.19182)
		(end 65.961006 -229.19182)
		(width 0.18288)
		(layer "In2.Cu")
		(net "M_A_CPU1_SB_DQS_DP<0>")
	)
	(segment
		(start 64.1985 -228.620066)
		(end 63.998348 -228.419914)
		(width 0.16002)
		(layer "In2.Cu")
		(net "M_A_CPU1_SB_DQS_DP<0>")
	)
	(segment
		(start 64.459104 -228.896418)
		(end 64.226694 -228.664008)
		(width 0.18288)
		(layer "In2.Cu")
		(net "M_A_CPU1_SB_DQS_DP<0>")
	)
	(segment
		(start 62.321948 -228.496622)
		(end 62.051946 -228.766624)
		(width 0.18288)
		(layer "In2.Cu")
		(net "M_A_CPU1_SB_DQS_DP<0>")
	)
	(segment
		(start 85.057996 -237.909862)
		(end 85.043264 -237.901226)
		(width 0.088646)
		(layer "In2.Cu")
		(net "M_A_CPU1_SB_DQS_DP<0>")
	)
	(segment
		(start 84.118196 -237.909862)
		(end 84.103464 -237.901226)
		(width 0.088646)
		(layer "In2.Cu")
		(net "M_A_CPU1_SB_DQS_DP<0>")
	)
	(segment
		(start 62.733428 -228.496622)
		(end 62.321948 -228.496622)
		(width 0.18288)
		(layer "In2.Cu")
		(net "M_A_CPU1_SB_DQS_DP<0>")
	)
	(segment
		(start 70.510146 -228.915976)
		(end 66.615564 -228.915976)
		(width 0.18288)
		(layer "In2.Cu")
		(net "M_A_CPU1_SB_DQS_DP<0>")
	)
	(segment
		(start 63.954406 -228.39172)
		(end 63.803784 -228.241098)
		(width 0.18288)
		(layer "In2.Cu")
		(net "M_A_CPU1_SB_DQS_DP<0>")
	)
	(segment
		(start 63.9826 -228.419914)
		(end 63.954406 -228.39172)
		(width 0.16002)
		(layer "In2.Cu")
		(net "M_A_CPU1_SB_DQS_DP<0>")
	)
	(segment
		(start 88.125808 -237.785656)
		(end 88.115394 -237.785148)
		(width 0.088646)
		(layer "In2.Cu")
		(net "M_A_CPU1_SB_DQS_DP<0>")
	)
	(segment
		(start 88.707214 -237.411768)
		(end 88.426036 -237.692946)
		(width 0.088646)
		(layer "In2.Cu")
		(net "M_A_CPU1_SB_DQS_DP<0>")
	)
	(segment
		(start 66.615564 -228.915976)
		(end 66.33972 -229.19182)
		(width 0.18288)
		(layer "In2.Cu")
		(net "M_A_CPU1_SB_DQS_DP<0>")
	)
	(arc
		(start 85.608668 -237.901226)
		(mid 85.334469 -237.977061)
		(end 85.057996 -237.909862)
		(width 0.088646)
		(layer "In2.Cu")
		(net "M_A_CPU1_SB_DQS_DP<0>")
	)
	(arc
		(start 85.983064 -237.901226)
		(mid 85.795866 -237.851083)
		(end 85.608668 -237.901226)
		(width 0.088646)
		(layer "In2.Cu")
		(net "M_A_CPU1_SB_DQS_DP<0>")
	)
	(arc
		(start 87.487252 -237.900972)
		(mid 87.205168 -237.976528)
		(end 86.923118 -237.900972)
		(width 0.088646)
		(layer "In2.Cu")
		(net "M_A_CPU1_SB_DQS_DP<0>")
	)
	(arc
		(start 88.33231 -237.736126)
		(mid 88.232643 -237.775827)
		(end 88.125808 -237.785656)
		(width 0.088646)
		(layer "In2.Cu")
		(net "M_A_CPU1_SB_DQS_DP<0>")
	)
	(arc
		(start 86.548468 -237.901226)
		(mid 86.265766 -237.977002)
		(end 85.983064 -237.901226)
		(width 0.088646)
		(layer "In2.Cu")
		(net "M_A_CPU1_SB_DQS_DP<0>")
	)
	(arc
		(start 85.043264 -237.901226)
		(mid 84.856066 -237.851083)
		(end 84.668868 -237.901226)
		(width 0.088646)
		(layer "In2.Cu")
		(net "M_A_CPU1_SB_DQS_DP<0>")
	)
	(arc
		(start 87.917528 -237.785656)
		(mid 87.694783 -237.814942)
		(end 87.487252 -237.900972)
		(width 0.088646)
		(layer "In2.Cu")
		(net "M_A_CPU1_SB_DQS_DP<0>")
	)
	(arc
		(start 84.668868 -237.901226)
		(mid 84.394669 -237.977061)
		(end 84.118196 -237.909862)
		(width 0.088646)
		(layer "In2.Cu")
		(net "M_A_CPU1_SB_DQS_DP<0>")
	)
	(arc
		(start 88.426036 -237.692946)
		(mid 88.378183 -237.712387)
		(end 88.33231 -237.736126)
		(width 0.088646)
		(layer "In2.Cu")
		(net "M_A_CPU1_SB_DQS_DP<0>")
	)
	(arc
		(start 86.922864 -237.901226)
		(mid 86.735666 -237.851083)
		(end 86.548468 -237.901226)
		(width 0.088646)
		(layer "In2.Cu")
		(net "M_A_CPU1_SB_DQS_DP<0>")
	)
	(arc
		(start 84.103464 -237.901226)
		(mid 83.983184 -237.851192)
		(end 83.854036 -237.83417)
		(width 0.088646)
		(layer "In2.Cu")
		(net "M_A_CPU1_SB_DQS_DP<0>")
	)
	(segment
		(start 59.008264 -237.691676)
		(end 59.225434 -237.908846)
		(width 0.20066)
		(layer "F.Cu")
		(net "M_A_CPU1_SB_DQS_DN<9>")
	)
	(segment
		(start 61.439806 -237.266734)
		(end 60.947046 -237.266734)
		(width 0.20066)
		(layer "F.Cu")
		(net "M_A_CPU1_SB_DQS_DN<9>")
	)
	(segment
		(start 54.22265 -237.537498)
		(end 54.761892 -237.537498)
		(width 0.20066)
		(layer "F.Cu")
		(net "M_A_CPU1_SB_DQS_DN<9>")
	)
	(segment
		(start 72.309482 -238.94542)
		(end 71.623174 -238.661194)
		(width 0.20066)
		(layer "F.Cu")
		(net "M_A_CPU1_SB_DQS_DN<9>")
	)
	(segment
		(start 84.198968 -240.40719)
		(end 83.9216 -240.292636)
		(width 0.088646)
		(layer "F.Cu")
		(net "M_A_CPU1_SB_DQS_DN<9>")
	)
	(segment
		(start 76.747116 -239.98809)
		(end 76.622656 -240.11255)
		(width 0.20066)
		(layer "F.Cu")
		(net "M_A_CPU1_SB_DQS_DN<9>")
	)
	(segment
		(start 73.651872 -239.501172)
		(end 73.095866 -239.271048)
		(width 0.20066)
		(layer "F.Cu")
		(net "M_A_CPU1_SB_DQS_DN<9>")
	)
	(segment
		(start 74.437748 -239.82553)
		(end 74.370946 -239.664494)
		(width 0.20066)
		(layer "F.Cu")
		(net "M_A_CPU1_SB_DQS_DN<9>")
	)
	(segment
		(start 79.528416 -240.11255)
		(end 78.926436 -240.11255)
		(width 0.20066)
		(layer "F.Cu")
		(net "M_A_CPU1_SB_DQS_DN<9>")
	)
	(segment
		(start 62.773052 -237.962694)
		(end 62.34811 -237.537752)
		(width 0.20066)
		(layer "F.Cu")
		(net "M_A_CPU1_SB_DQS_DN<9>")
	)
	(segment
		(start 55.729632 -237.960154)
		(end 55.99811 -237.691676)
		(width 0.20066)
		(layer "F.Cu")
		(net "M_A_CPU1_SB_DQS_DN<9>")
	)
	(segment
		(start 72.472042 -238.877856)
		(end 72.309482 -238.94542)
		(width 0.20066)
		(layer "F.Cu")
		(net "M_A_CPU1_SB_DQS_DN<9>")
	)
	(segment
		(start 61.44006 -237.26648)
		(end 61.439806 -237.266734)
		(width 0.20066)
		(layer "F.Cu")
		(net "M_A_CPU1_SB_DQS_DN<9>")
	)
	(segment
		(start 68.238878 -238.661194)
		(end 67.791584 -238.2139)
		(width 0.20066)
		(layer "F.Cu")
		(net "M_A_CPU1_SB_DQS_DN<9>")
	)
	(segment
		(start 80.254856 -239.98809)
		(end 79.652876 -239.98809)
		(width 0.20066)
		(layer "F.Cu")
		(net "M_A_CPU1_SB_DQS_DN<9>")
	)
	(segment
		(start 75.130914 -240.11255)
		(end 74.437748 -239.82553)
		(width 0.20066)
		(layer "F.Cu")
		(net "M_A_CPU1_SB_DQS_DN<9>")
	)
	(segment
		(start 60.117228 -237.507272)
		(end 60.357766 -237.266734)
		(width 0.20066)
		(layer "F.Cu")
		(net "M_A_CPU1_SB_DQS_DN<9>")
	)
	(segment
		(start 60.357766 -237.266734)
		(end 60.947046 -237.266734)
		(width 0.20066)
		(layer "F.Cu")
		(net "M_A_CPU1_SB_DQS_DN<9>")
	)
	(segment
		(start 67.034156 -238.2139)
		(end 66.797682 -237.977426)
		(width 0.20066)
		(layer "F.Cu")
		(net "M_A_CPU1_SB_DQS_DN<9>")
	)
	(segment
		(start 77.473556 -240.11255)
		(end 77.349096 -239.98809)
		(width 0.20066)
		(layer "F.Cu")
		(net "M_A_CPU1_SB_DQS_DN<9>")
	)
	(segment
		(start 68.965318 -238.536734)
		(end 68.840858 -238.661194)
		(width 0.20066)
		(layer "F.Cu")
		(net "M_A_CPU1_SB_DQS_DN<9>")
	)
	(segment
		(start 83.349592 -240.18113)
		(end 82.990944 -240.18113)
		(width 0.088646)
		(layer "F.Cu")
		(net "M_A_CPU1_SB_DQS_DN<9>")
	)
	(segment
		(start 61.711332 -237.537752)
		(end 61.44006 -237.26648)
		(width 0.20066)
		(layer "F.Cu")
		(net "M_A_CPU1_SB_DQS_DN<9>")
	)
	(segment
		(start 53.403246 -237.266734)
		(end 53.951886 -237.266734)
		(width 0.20066)
		(layer "F.Cu")
		(net "M_A_CPU1_SB_DQS_DN<9>")
	)
	(segment
		(start 79.652876 -239.98809)
		(end 79.528416 -240.11255)
		(width 0.20066)
		(layer "F.Cu")
		(net "M_A_CPU1_SB_DQS_DN<9>")
	)
	(segment
		(start 66.51752 -237.691676)
		(end 63.582296 -237.691676)
		(width 0.1016)
		(layer "F.Cu")
		(net "M_A_CPU1_SB_DQS_DN<9>")
	)
	(segment
		(start 55.184548 -237.960154)
		(end 55.729632 -237.960154)
		(width 0.20066)
		(layer "F.Cu")
		(net "M_A_CPU1_SB_DQS_DN<9>")
	)
	(segment
		(start 83.61934 -240.29289)
		(end 83.349592 -240.18113)
		(width 0.088646)
		(layer "F.Cu")
		(net "M_A_CPU1_SB_DQS_DN<9>")
	)
	(segment
		(start 78.801976 -239.98809)
		(end 78.199996 -239.98809)
		(width 0.20066)
		(layer "F.Cu")
		(net "M_A_CPU1_SB_DQS_DN<9>")
	)
	(segment
		(start 82.990944 -240.18113)
		(end 82.959194 -240.14938)
		(width 0.088646)
		(layer "F.Cu")
		(net "M_A_CPU1_SB_DQS_DN<9>")
	)
	(segment
		(start 73.095866 -239.271048)
		(end 73.028556 -239.108488)
		(width 0.20066)
		(layer "F.Cu")
		(net "M_A_CPU1_SB_DQS_DN<9>")
	)
	(segment
		(start 69.567298 -238.536734)
		(end 68.965318 -238.536734)
		(width 0.20066)
		(layer "F.Cu")
		(net "M_A_CPU1_SB_DQS_DN<9>")
	)
	(segment
		(start 78.199996 -239.98809)
		(end 78.075536 -240.11255)
		(width 0.20066)
		(layer "F.Cu")
		(net "M_A_CPU1_SB_DQS_DN<9>")
	)
	(segment
		(start 77.349096 -239.98809)
		(end 76.747116 -239.98809)
		(width 0.20066)
		(layer "F.Cu")
		(net "M_A_CPU1_SB_DQS_DN<9>")
	)
	(segment
		(start 82.959194 -240.14938)
		(end 82.937096 -240.14938)
		(width 0.088646)
		(layer "F.Cu")
		(net "M_A_CPU1_SB_DQS_DN<9>")
	)
	(segment
		(start 59.852306 -237.507272)
		(end 60.117228 -237.507272)
		(width 0.20066)
		(layer "F.Cu")
		(net "M_A_CPU1_SB_DQS_DN<9>")
	)
	(segment
		(start 56.032146 -237.691676)
		(end 58.967878 -237.691676)
		(width 0.1016)
		(layer "F.Cu")
		(net "M_A_CPU1_SB_DQS_DN<9>")
	)
	(segment
		(start 71.623174 -238.661194)
		(end 71.144638 -238.661194)
		(width 0.20066)
		(layer "F.Cu")
		(net "M_A_CPU1_SB_DQS_DN<9>")
	)
	(segment
		(start 63.2587 -237.962694)
		(end 62.773052 -237.962694)
		(width 0.20066)
		(layer "F.Cu")
		(net "M_A_CPU1_SB_DQS_DN<9>")
	)
	(segment
		(start 67.791584 -238.2139)
		(end 67.034156 -238.2139)
		(width 0.20066)
		(layer "F.Cu")
		(net "M_A_CPU1_SB_DQS_DN<9>")
	)
	(segment
		(start 84.765388 -240.426748)
		(end 84.296758 -240.426748)
		(width 0.088646)
		(layer "F.Cu")
		(net "M_A_CPU1_SB_DQS_DN<9>")
	)
	(segment
		(start 55.99811 -237.691676)
		(end 56.032146 -237.691676)
		(width 0.20066)
		(layer "F.Cu")
		(net "M_A_CPU1_SB_DQS_DN<9>")
	)
	(segment
		(start 81.056226 -240.14938)
		(end 81.019396 -240.11255)
		(width 0.1524)
		(layer "F.Cu")
		(net "M_A_CPU1_SB_DQS_DN<9>")
	)
	(segment
		(start 66.797682 -237.8837)
		(end 66.605658 -237.691676)
		(width 0.20066)
		(layer "F.Cu")
		(net "M_A_CPU1_SB_DQS_DN<9>")
	)
	(segment
		(start 53.951886 -237.266734)
		(end 54.22265 -237.537498)
		(width 0.20066)
		(layer "F.Cu")
		(net "M_A_CPU1_SB_DQS_DN<9>")
	)
	(segment
		(start 69.691758 -238.661194)
		(end 69.567298 -238.536734)
		(width 0.20066)
		(layer "F.Cu")
		(net "M_A_CPU1_SB_DQS_DN<9>")
	)
	(segment
		(start 59.225434 -237.908846)
		(end 59.410854 -237.908846)
		(width 0.20066)
		(layer "F.Cu")
		(net "M_A_CPU1_SB_DQS_DN<9>")
	)
	(segment
		(start 59.410854 -237.908846)
		(end 59.47918 -237.880398)
		(width 0.20066)
		(layer "F.Cu")
		(net "M_A_CPU1_SB_DQS_DN<9>")
	)
	(segment
		(start 66.797682 -237.977426)
		(end 66.797682 -237.8837)
		(width 0.20066)
		(layer "F.Cu")
		(net "M_A_CPU1_SB_DQS_DN<9>")
	)
	(segment
		(start 78.075536 -240.11255)
		(end 77.473556 -240.11255)
		(width 0.20066)
		(layer "F.Cu")
		(net "M_A_CPU1_SB_DQS_DN<9>")
	)
	(segment
		(start 74.370946 -239.664494)
		(end 73.814432 -239.433862)
		(width 0.20066)
		(layer "F.Cu")
		(net "M_A_CPU1_SB_DQS_DN<9>")
	)
	(segment
		(start 78.926436 -240.11255)
		(end 78.801976 -239.98809)
		(width 0.20066)
		(layer "F.Cu")
		(net "M_A_CPU1_SB_DQS_DN<9>")
	)
	(segment
		(start 66.605658 -237.691676)
		(end 66.51752 -237.691676)
		(width 0.20066)
		(layer "F.Cu")
		(net "M_A_CPU1_SB_DQS_DN<9>")
	)
	(segment
		(start 80.981296 -240.11255)
		(end 80.379316 -240.11255)
		(width 0.20066)
		(layer "F.Cu")
		(net "M_A_CPU1_SB_DQS_DN<9>")
	)
	(segment
		(start 82.937096 -240.14938)
		(end 81.056226 -240.14938)
		(width 0.1524)
		(layer "F.Cu")
		(net "M_A_CPU1_SB_DQS_DN<9>")
	)
	(segment
		(start 76.622656 -240.11255)
		(end 75.130914 -240.11255)
		(width 0.20066)
		(layer "F.Cu")
		(net "M_A_CPU1_SB_DQS_DN<9>")
	)
	(segment
		(start 59.47918 -237.880398)
		(end 59.852306 -237.507272)
		(width 0.20066)
		(layer "F.Cu")
		(net "M_A_CPU1_SB_DQS_DN<9>")
	)
	(segment
		(start 73.028556 -239.108488)
		(end 72.472042 -238.877856)
		(width 0.20066)
		(layer "F.Cu")
		(net "M_A_CPU1_SB_DQS_DN<9>")
	)
	(segment
		(start 62.34811 -237.537752)
		(end 61.711332 -237.537752)
		(width 0.20066)
		(layer "F.Cu")
		(net "M_A_CPU1_SB_DQS_DN<9>")
	)
	(segment
		(start 81.019396 -240.11255)
		(end 80.981296 -240.11255)
		(width 0.1524)
		(layer "F.Cu")
		(net "M_A_CPU1_SB_DQS_DN<9>")
	)
	(segment
		(start 83.9216 -240.292636)
		(end 83.61934 -240.29289)
		(width 0.088646)
		(layer "F.Cu")
		(net "M_A_CPU1_SB_DQS_DN<9>")
	)
	(segment
		(start 84.296758 -240.426748)
		(end 84.198968 -240.40719)
		(width 0.088646)
		(layer "F.Cu")
		(net "M_A_CPU1_SB_DQS_DN<9>")
	)
	(segment
		(start 73.814432 -239.433862)
		(end 73.651872 -239.501172)
		(width 0.20066)
		(layer "F.Cu")
		(net "M_A_CPU1_SB_DQS_DN<9>")
	)
	(segment
		(start 58.967878 -237.691676)
		(end 59.008264 -237.691676)
		(width 0.20066)
		(layer "F.Cu")
		(net "M_A_CPU1_SB_DQS_DN<9>")
	)
	(segment
		(start 63.529718 -237.691676)
		(end 63.2587 -237.962694)
		(width 0.20066)
		(layer "F.Cu")
		(net "M_A_CPU1_SB_DQS_DN<9>")
	)
	(segment
		(start 63.582296 -237.691676)
		(end 63.529718 -237.691676)
		(width 0.20066)
		(layer "F.Cu")
		(net "M_A_CPU1_SB_DQS_DN<9>")
	)
	(segment
		(start 80.379316 -240.11255)
		(end 80.254856 -239.98809)
		(width 0.20066)
		(layer "F.Cu")
		(net "M_A_CPU1_SB_DQS_DN<9>")
	)
	(segment
		(start 71.020178 -238.536734)
		(end 70.418198 -238.536734)
		(width 0.20066)
		(layer "F.Cu")
		(net "M_A_CPU1_SB_DQS_DN<9>")
	)
	(segment
		(start 70.418198 -238.536734)
		(end 70.293738 -238.661194)
		(width 0.20066)
		(layer "F.Cu")
		(net "M_A_CPU1_SB_DQS_DN<9>")
	)
	(segment
		(start 70.293738 -238.661194)
		(end 69.691758 -238.661194)
		(width 0.20066)
		(layer "F.Cu")
		(net "M_A_CPU1_SB_DQS_DN<9>")
	)
	(segment
		(start 54.761892 -237.537498)
		(end 55.184548 -237.960154)
		(width 0.20066)
		(layer "F.Cu")
		(net "M_A_CPU1_SB_DQS_DN<9>")
	)
	(segment
		(start 68.840858 -238.661194)
		(end 68.238878 -238.661194)
		(width 0.20066)
		(layer "F.Cu")
		(net "M_A_CPU1_SB_DQS_DN<9>")
	)
	(segment
		(start 71.144638 -238.661194)
		(end 71.020178 -238.536734)
		(width 0.20066)
		(layer "F.Cu")
		(net "M_A_CPU1_SB_DQS_DN<9>")
	)
	(arc
		(start 84.856066 -240.389156)
		(mid 84.814463 -240.416955)
		(end 84.765388 -240.426748)
		(width 0.088646)
		(layer "F.Cu")
		(net "M_A_CPU1_SB_DQS_DN<9>")
	)
	(segment
		(start 58.250328 -199.605646)
		(end 58.709306 -199.605646)
		(width 0.20066)
		(layer "F.Cu")
		(net "M_A_CPU1_SB_DQS_DN<8>")
	)
	(segment
		(start 85.080094 -220.551502)
		(end 85.079332 -220.550994)
		(width 0.088646)
		(layer "F.Cu")
		(net "M_A_CPU1_SB_DQS_DN<8>")
	)
	(segment
		(start 84.40039 -214.033608)
		(end 84.40039 -209.91957)
		(width 0.20066)
		(layer "F.Cu")
		(net "M_A_CPU1_SB_DQS_DN<8>")
	)
	(segment
		(start 83.980528 -219.726256)
		(end 83.965034 -219.710762)
		(width 0.088646)
		(layer "F.Cu")
		(net "M_A_CPU1_SB_DQS_DN<8>")
	)
	(segment
		(start 87.304118 -220.956632)
		(end 86.922864 -221.180152)
		(width 0.088646)
		(layer "F.Cu")
		(net "M_A_CPU1_SB_DQS_DN<8>")
	)
	(segment
		(start 84.850732 -220.366082)
		(end 84.66582 -220.366336)
		(width 0.088646)
		(layer "F.Cu")
		(net "M_A_CPU1_SB_DQS_DN<8>")
	)
	(segment
		(start 62.313566 -199.441816)
		(end 62.564518 -199.190864)
		(width 0.20066)
		(layer "F.Cu")
		(net "M_A_CPU1_SB_DQS_DN<8>")
	)
	(segment
		(start 65.899284 -199.600566)
		(end 65.633092 -199.866758)
		(width 0.20066)
		(layer "F.Cu")
		(net "M_A_CPU1_SB_DQS_DN<8>")
	)
	(segment
		(start 84.40039 -209.91957)
		(end 84.289646 -209.652108)
		(width 0.20066)
		(layer "F.Cu")
		(net "M_A_CPU1_SB_DQS_DN<8>")
	)
	(segment
		(start 59.63666 -199.448928)
		(end 59.822842 -199.448928)
		(width 0.20066)
		(layer "F.Cu")
		(net "M_A_CPU1_SB_DQS_DN<8>")
	)
	(segment
		(start 64.28232 -199.605646)
		(end 64.543432 -199.866758)
		(width 0.20066)
		(layer "F.Cu")
		(net "M_A_CPU1_SB_DQS_DN<8>")
	)
	(segment
		(start 74.238104 -199.600566)
		(end 65.899284 -199.600566)
		(width 0.20066)
		(layer "F.Cu")
		(net "M_A_CPU1_SB_DQS_DN<8>")
	)
	(segment
		(start 58.709306 -199.605646)
		(end 59.136026 -199.178926)
		(width 0.20066)
		(layer "F.Cu")
		(net "M_A_CPU1_SB_DQS_DN<8>")
	)
	(segment
		(start 85.077046 -220.549978)
		(end 85.076284 -220.54947)
		(width 0.088646)
		(layer "F.Cu")
		(net "M_A_CPU1_SB_DQS_DN<8>")
	)
	(segment
		(start 57.503314 -199.866758)
		(end 57.989216 -199.866758)
		(width 0.20066)
		(layer "F.Cu")
		(net "M_A_CPU1_SB_DQS_DN<8>")
	)
	(segment
		(start 65.633092 -199.866758)
		(end 65.047114 -199.866758)
		(width 0.20066)
		(layer "F.Cu")
		(net "M_A_CPU1_SB_DQS_DN<8>")
	)
	(segment
		(start 84.40039 -214.071708)
		(end 84.40039 -214.033608)
		(width 0.1524)
		(layer "F.Cu")
		(net "M_A_CPU1_SB_DQS_DN<8>")
	)
	(segment
		(start 83.965034 -219.710762)
		(end 83.255104 -219.000832)
		(width 0.1524)
		(layer "F.Cu")
		(net "M_A_CPU1_SB_DQS_DN<8>")
	)
	(segment
		(start 85.084412 -220.553788)
		(end 85.081872 -220.552518)
		(width 0.088646)
		(layer "F.Cu")
		(net "M_A_CPU1_SB_DQS_DN<8>")
	)
	(segment
		(start 63.558674 -199.605646)
		(end 64.28232 -199.605646)
		(width 0.20066)
		(layer "F.Cu")
		(net "M_A_CPU1_SB_DQS_DN<8>")
	)
	(segment
		(start 84.43722 -214.108538)
		(end 84.40039 -214.071708)
		(width 0.1524)
		(layer "F.Cu")
		(net "M_A_CPU1_SB_DQS_DN<8>")
	)
	(segment
		(start 83.255104 -215.670384)
		(end 84.43722 -214.488268)
		(width 0.1524)
		(layer "F.Cu")
		(net "M_A_CPU1_SB_DQS_DN<8>")
	)
	(segment
		(start 62.147958 -199.441816)
		(end 62.313566 -199.441816)
		(width 0.20066)
		(layer "F.Cu")
		(net "M_A_CPU1_SB_DQS_DN<8>")
	)
	(segment
		(start 86.365842 -220.916246)
		(end 86.359238 -220.827346)
		(width 0.088646)
		(layer "F.Cu")
		(net "M_A_CPU1_SB_DQS_DN<8>")
	)
	(segment
		(start 85.09254 -220.558106)
		(end 85.084412 -220.553788)
		(width 0.088646)
		(layer "F.Cu")
		(net "M_A_CPU1_SB_DQS_DN<8>")
	)
	(segment
		(start 84.289646 -209.652108)
		(end 74.238104 -199.600566)
		(width 0.20066)
		(layer "F.Cu")
		(net "M_A_CPU1_SB_DQS_DN<8>")
	)
	(segment
		(start 84.02574 -219.726256)
		(end 83.980528 -219.726256)
		(width 0.088646)
		(layer "F.Cu")
		(net "M_A_CPU1_SB_DQS_DN<8>")
	)
	(segment
		(start 84.92617 -220.44152)
		(end 84.850732 -220.366082)
		(width 0.088646)
		(layer "F.Cu")
		(net "M_A_CPU1_SB_DQS_DN<8>")
	)
	(segment
		(start 86.283292 -220.679264)
		(end 85.99297 -220.533976)
		(width 0.088646)
		(layer "F.Cu")
		(net "M_A_CPU1_SB_DQS_DN<8>")
	)
	(segment
		(start 59.822842 -199.448928)
		(end 59.829954 -199.441816)
		(width 0.1016)
		(layer "F.Cu")
		(net "M_A_CPU1_SB_DQS_DN<8>")
	)
	(segment
		(start 64.543432 -199.866758)
		(end 65.047114 -199.866758)
		(width 0.20066)
		(layer "F.Cu")
		(net "M_A_CPU1_SB_DQS_DN<8>")
	)
	(segment
		(start 86.359238 -220.827346)
		(end 86.283292 -220.679264)
		(width 0.088646)
		(layer "F.Cu")
		(net "M_A_CPU1_SB_DQS_DN<8>")
	)
	(segment
		(start 59.136026 -199.178926)
		(end 59.366658 -199.178926)
		(width 0.20066)
		(layer "F.Cu")
		(net "M_A_CPU1_SB_DQS_DN<8>")
	)
	(segment
		(start 85.051646 -220.536008)
		(end 85.048852 -220.534484)
		(width 0.088646)
		(layer "F.Cu")
		(net "M_A_CPU1_SB_DQS_DN<8>")
	)
	(segment
		(start 85.071458 -220.54693)
		(end 85.051646 -220.536008)
		(width 0.088646)
		(layer "F.Cu")
		(net "M_A_CPU1_SB_DQS_DN<8>")
	)
	(segment
		(start 57.989216 -199.866758)
		(end 58.250328 -199.605646)
		(width 0.20066)
		(layer "F.Cu")
		(net "M_A_CPU1_SB_DQS_DN<8>")
	)
	(segment
		(start 85.07603 -220.54947)
		(end 85.073998 -220.548454)
		(width 0.088646)
		(layer "F.Cu")
		(net "M_A_CPU1_SB_DQS_DN<8>")
	)
	(segment
		(start 83.255104 -219.000832)
		(end 83.255104 -215.670384)
		(width 0.1524)
		(layer "F.Cu")
		(net "M_A_CPU1_SB_DQS_DN<8>")
	)
	(segment
		(start 85.553804 -220.532198)
		(end 85.452458 -220.578426)
		(width 0.088646)
		(layer "F.Cu")
		(net "M_A_CPU1_SB_DQS_DN<8>")
	)
	(segment
		(start 84.43722 -214.488268)
		(end 84.43722 -214.108538)
		(width 0.1524)
		(layer "F.Cu")
		(net "M_A_CPU1_SB_DQS_DN<8>")
	)
	(segment
		(start 59.829954 -199.441816)
		(end 62.147958 -199.441816)
		(width 0.1016)
		(layer "F.Cu")
		(net "M_A_CPU1_SB_DQS_DN<8>")
	)
	(segment
		(start 85.081872 -220.552518)
		(end 85.080094 -220.551502)
		(width 0.088646)
		(layer "F.Cu")
		(net "M_A_CPU1_SB_DQS_DN<8>")
	)
	(segment
		(start 59.366658 -199.178926)
		(end 59.63666 -199.448928)
		(width 0.20066)
		(layer "F.Cu")
		(net "M_A_CPU1_SB_DQS_DN<8>")
	)
	(segment
		(start 85.907372 -220.513656)
		(end 85.639656 -220.513656)
		(width 0.088646)
		(layer "F.Cu")
		(net "M_A_CPU1_SB_DQS_DN<8>")
	)
	(segment
		(start 62.564518 -199.190864)
		(end 62.937898 -199.190864)
		(width 0.20066)
		(layer "F.Cu")
		(net "M_A_CPU1_SB_DQS_DN<8>")
	)
	(segment
		(start 85.076284 -220.54947)
		(end 85.07603 -220.54947)
		(width 0.088646)
		(layer "F.Cu")
		(net "M_A_CPU1_SB_DQS_DN<8>")
	)
	(segment
		(start 85.073998 -220.548454)
		(end 85.071458 -220.54693)
		(width 0.088646)
		(layer "F.Cu")
		(net "M_A_CPU1_SB_DQS_DN<8>")
	)
	(segment
		(start 85.079332 -220.550994)
		(end 85.077046 -220.549978)
		(width 0.088646)
		(layer "F.Cu")
		(net "M_A_CPU1_SB_DQS_DN<8>")
	)
	(segment
		(start 84.66582 -220.366336)
		(end 84.02574 -219.726256)
		(width 0.088646)
		(layer "F.Cu")
		(net "M_A_CPU1_SB_DQS_DN<8>")
	)
	(segment
		(start 62.937898 -199.190864)
		(end 63.558674 -199.605646)
		(width 0.20066)
		(layer "F.Cu")
		(net "M_A_CPU1_SB_DQS_DN<8>")
	)
	(arc
		(start 86.922864 -221.180152)
		(mid 86.735666 -221.230295)
		(end 86.548468 -221.180152)
		(width 0.088646)
		(layer "F.Cu")
		(net "M_A_CPU1_SB_DQS_DN<8>")
	)
	(arc
		(start 85.639656 -220.513656)
		(mid 85.595745 -220.518355)
		(end 85.553804 -220.532198)
		(width 0.088646)
		(layer "F.Cu")
		(net "M_A_CPU1_SB_DQS_DN<8>")
	)
	(arc
		(start 85.452458 -220.578426)
		(mid 85.369097 -220.60515)
		(end 85.28177 -220.611192)
		(width 0.088646)
		(layer "F.Cu")
		(net "M_A_CPU1_SB_DQS_DN<8>")
	)
	(arc
		(start 85.99297 -220.533976)
		(mid 85.95136 -220.518794)
		(end 85.907372 -220.513656)
		(width 0.088646)
		(layer "F.Cu")
		(net "M_A_CPU1_SB_DQS_DN<8>")
	)
	(arc
		(start 85.28177 -220.611192)
		(mid 85.184351 -220.594649)
		(end 85.09254 -220.558106)
		(width 0.088646)
		(layer "F.Cu")
		(net "M_A_CPU1_SB_DQS_DN<8>")
	)
	(arc
		(start 85.048852 -220.534484)
		(mid 84.984334 -220.492196)
		(end 84.92617 -220.44152)
		(width 0.088646)
		(layer "F.Cu")
		(net "M_A_CPU1_SB_DQS_DN<8>")
	)
	(arc
		(start 86.548468 -221.180152)
		(mid 86.427501 -221.06872)
		(end 86.365842 -220.916246)
		(width 0.088646)
		(layer "F.Cu")
		(net "M_A_CPU1_SB_DQS_DN<8>")
	)
	(arc
		(start 87.675466 -220.855794)
		(mid 87.48307 -220.881456)
		(end 87.304118 -220.956632)
		(width 0.088646)
		(layer "F.Cu")
		(net "M_A_CPU1_SB_DQS_DN<8>")
	)
	(segment
		(start 85.608414 -230.29799)
		(end 85.608668 -230.298244)
		(width 0.088646)
		(layer "F.Cu")
		(net "M_A_CPU1_SB_DQS_DN<7>")
	)
	(segment
		(start 84.567268 -230.28021)
		(end 83.986116 -230.28021)
		(width 0.088646)
		(layer "F.Cu")
		(net "M_A_CPU1_SB_DQS_DN<7>")
	)
	(segment
		(start 80.191864 -226.858068)
		(end 80.191864 -224.718626)
		(width 0.1524)
		(layer "F.Cu")
		(net "M_A_CPU1_SB_DQS_DN<7>")
	)
	(segment
		(start 62.503558 -208.806542)
		(end 62.777116 -208.532984)
		(width 0.20066)
		(layer "F.Cu")
		(net "M_A_CPU1_SB_DQS_DN<7>")
	)
	(segment
		(start 57.503314 -209.216752)
		(end 57.989216 -209.216752)
		(width 0.20066)
		(layer "F.Cu")
		(net "M_A_CPU1_SB_DQS_DN<7>")
	)
	(segment
		(start 85.057996 -230.30688)
		(end 85.043264 -230.298244)
		(width 0.088646)
		(layer "F.Cu")
		(net "M_A_CPU1_SB_DQS_DN<7>")
	)
	(segment
		(start 65.969134 -209.118708)
		(end 65.96634 -209.121502)
		(width 0.20066)
		(layer "F.Cu")
		(net "M_A_CPU1_SB_DQS_DN<7>")
	)
	(segment
		(start 78.586584 -216.966038)
		(end 78.473046 -216.691972)
		(width 0.1524)
		(layer "F.Cu")
		(net "M_A_CPU1_SB_DQS_DN<7>")
	)
	(segment
		(start 65.96634 -209.121502)
		(end 65.943988 -209.121502)
		(width 0.20066)
		(layer "F.Cu")
		(net "M_A_CPU1_SB_DQS_DN<7>")
	)
	(segment
		(start 86.360254 -230.604314)
		(end 86.358984 -230.59009)
		(width 0.088646)
		(layer "F.Cu")
		(net "M_A_CPU1_SB_DQS_DN<7>")
	)
	(segment
		(start 65.848738 -209.216752)
		(end 65.047114 -209.216752)
		(width 0.20066)
		(layer "F.Cu")
		(net "M_A_CPU1_SB_DQS_DN<7>")
	)
	(segment
		(start 83.954112 -230.312214)
		(end 83.932014 -230.312214)
		(width 0.088646)
		(layer "F.Cu")
		(net "M_A_CPU1_SB_DQS_DN<7>")
	)
	(segment
		(start 65.943988 -209.121502)
		(end 65.848738 -209.216752)
		(width 0.20066)
		(layer "F.Cu")
		(net "M_A_CPU1_SB_DQS_DN<7>")
	)
	(segment
		(start 83.932014 -230.312214)
		(end 83.64601 -230.312214)
		(width 0.1524)
		(layer "F.Cu")
		(net "M_A_CPU1_SB_DQS_DN<7>")
	)
	(segment
		(start 78.473046 -215.877648)
		(end 78.434692 -215.839294)
		(width 0.1524)
		(layer "F.Cu")
		(net "M_A_CPU1_SB_DQS_DN<7>")
	)
	(segment
		(start 86.358984 -230.59009)
		(end 86.287356 -230.449374)
		(width 0.088646)
		(layer "F.Cu")
		(net "M_A_CPU1_SB_DQS_DN<7>")
	)
	(segment
		(start 71.661528 -209.118708)
		(end 65.969134 -209.118708)
		(width 0.20066)
		(layer "F.Cu")
		(net "M_A_CPU1_SB_DQS_DN<7>")
	)
	(segment
		(start 59.170062 -208.52892)
		(end 59.447684 -208.806542)
		(width 0.20066)
		(layer "F.Cu")
		(net "M_A_CPU1_SB_DQS_DN<7>")
	)
	(segment
		(start 83.986116 -230.28021)
		(end 83.954112 -230.312214)
		(width 0.088646)
		(layer "F.Cu")
		(net "M_A_CPU1_SB_DQS_DN<7>")
	)
	(segment
		(start 85.982302 -230.296974)
		(end 85.98154 -230.29672)
		(width 0.088646)
		(layer "F.Cu")
		(net "M_A_CPU1_SB_DQS_DN<7>")
	)
	(segment
		(start 64.28232 -208.95564)
		(end 64.543432 -209.216752)
		(width 0.20066)
		(layer "F.Cu")
		(net "M_A_CPU1_SB_DQS_DN<7>")
	)
	(segment
		(start 85.98154 -230.29672)
		(end 85.979762 -230.295704)
		(width 0.088646)
		(layer "F.Cu")
		(net "M_A_CPU1_SB_DQS_DN<7>")
	)
	(segment
		(start 78.434692 -215.839294)
		(end 78.286356 -215.691212)
		(width 0.1524)
		(layer "F.Cu")
		(net "M_A_CPU1_SB_DQS_DN<7>")
	)
	(segment
		(start 87.304118 -230.72344)
		(end 86.922864 -230.94696)
		(width 0.088646)
		(layer "F.Cu")
		(net "M_A_CPU1_SB_DQS_DN<7>")
	)
	(segment
		(start 62.133226 -208.79181)
		(end 62.147958 -208.806542)
		(width 0.1016)
		(layer "F.Cu")
		(net "M_A_CPU1_SB_DQS_DN<7>")
	)
	(segment
		(start 59.031886 -208.52892)
		(end 59.170062 -208.52892)
		(width 0.20066)
		(layer "F.Cu")
		(net "M_A_CPU1_SB_DQS_DN<7>")
	)
	(segment
		(start 57.989216 -209.216752)
		(end 58.250328 -208.95564)
		(width 0.20066)
		(layer "F.Cu")
		(net "M_A_CPU1_SB_DQS_DN<7>")
	)
	(segment
		(start 86.36 -230.604314)
		(end 86.360254 -230.604314)
		(width 0.088646)
		(layer "F.Cu")
		(net "M_A_CPU1_SB_DQS_DN<7>")
	)
	(segment
		(start 59.891676 -208.79181)
		(end 62.133226 -208.79181)
		(width 0.1016)
		(layer "F.Cu")
		(net "M_A_CPU1_SB_DQS_DN<7>")
	)
	(segment
		(start 58.605166 -208.95564)
		(end 59.031886 -208.52892)
		(width 0.20066)
		(layer "F.Cu")
		(net "M_A_CPU1_SB_DQS_DN<7>")
	)
	(segment
		(start 84.59978 -230.247698)
		(end 84.567268 -230.28021)
		(width 0.088646)
		(layer "F.Cu")
		(net "M_A_CPU1_SB_DQS_DN<7>")
	)
	(segment
		(start 63.13424 -208.532984)
		(end 63.7667 -208.95564)
		(width 0.20066)
		(layer "F.Cu")
		(net "M_A_CPU1_SB_DQS_DN<7>")
	)
	(segment
		(start 64.543432 -209.216752)
		(end 65.047114 -209.216752)
		(width 0.20066)
		(layer "F.Cu")
		(net "M_A_CPU1_SB_DQS_DN<7>")
	)
	(segment
		(start 84.856066 -230.247698)
		(end 84.59978 -230.247698)
		(width 0.088646)
		(layer "F.Cu")
		(net "M_A_CPU1_SB_DQS_DN<7>")
	)
	(segment
		(start 86.365842 -230.683054)
		(end 86.36 -230.604314)
		(width 0.088646)
		(layer "F.Cu")
		(net "M_A_CPU1_SB_DQS_DN<7>")
	)
	(segment
		(start 85.979762 -230.295704)
		(end 85.97646 -230.293926)
		(width 0.088646)
		(layer "F.Cu")
		(net "M_A_CPU1_SB_DQS_DN<7>")
	)
	(segment
		(start 80.191864 -224.718626)
		(end 78.586584 -223.113346)
		(width 0.1524)
		(layer "F.Cu")
		(net "M_A_CPU1_SB_DQS_DN<7>")
	)
	(segment
		(start 78.207108 -215.664288)
		(end 71.661528 -209.118708)
		(width 0.20066)
		(layer "F.Cu")
		(net "M_A_CPU1_SB_DQS_DN<7>")
	)
	(segment
		(start 83.64601 -230.312214)
		(end 80.191864 -226.858068)
		(width 0.1524)
		(layer "F.Cu")
		(net "M_A_CPU1_SB_DQS_DN<7>")
	)
	(segment
		(start 78.586584 -223.113346)
		(end 78.586584 -216.966038)
		(width 0.1524)
		(layer "F.Cu")
		(net "M_A_CPU1_SB_DQS_DN<7>")
	)
	(segment
		(start 62.777116 -208.532984)
		(end 63.13424 -208.532984)
		(width 0.20066)
		(layer "F.Cu")
		(net "M_A_CPU1_SB_DQS_DN<7>")
	)
	(segment
		(start 78.286356 -215.691212)
		(end 78.234032 -215.691212)
		(width 0.1524)
		(layer "F.Cu")
		(net "M_A_CPU1_SB_DQS_DN<7>")
	)
	(segment
		(start 86.287356 -230.449374)
		(end 85.982302 -230.296974)
		(width 0.088646)
		(layer "F.Cu")
		(net "M_A_CPU1_SB_DQS_DN<7>")
	)
	(segment
		(start 78.473046 -216.691972)
		(end 78.473046 -215.877648)
		(width 0.1524)
		(layer "F.Cu")
		(net "M_A_CPU1_SB_DQS_DN<7>")
	)
	(segment
		(start 59.447684 -208.806542)
		(end 59.822842 -208.806542)
		(width 0.20066)
		(layer "F.Cu")
		(net "M_A_CPU1_SB_DQS_DN<7>")
	)
	(segment
		(start 86.548468 -230.94696)
		(end 86.548214 -230.946706)
		(width 0.088646)
		(layer "F.Cu")
		(net "M_A_CPU1_SB_DQS_DN<7>")
	)
	(segment
		(start 58.250328 -208.95564)
		(end 58.605166 -208.95564)
		(width 0.20066)
		(layer "F.Cu")
		(net "M_A_CPU1_SB_DQS_DN<7>")
	)
	(segment
		(start 78.234032 -215.691212)
		(end 78.207108 -215.664288)
		(width 0.1524)
		(layer "F.Cu")
		(net "M_A_CPU1_SB_DQS_DN<7>")
	)
	(segment
		(start 62.147958 -208.806542)
		(end 62.503558 -208.806542)
		(width 0.20066)
		(layer "F.Cu")
		(net "M_A_CPU1_SB_DQS_DN<7>")
	)
	(segment
		(start 63.7667 -208.95564)
		(end 64.28232 -208.95564)
		(width 0.20066)
		(layer "F.Cu")
		(net "M_A_CPU1_SB_DQS_DN<7>")
	)
	(segment
		(start 59.822842 -208.806542)
		(end 59.891676 -208.79181)
		(width 0.1016)
		(layer "F.Cu")
		(net "M_A_CPU1_SB_DQS_DN<7>")
	)
	(arc
		(start 85.608668 -230.298244)
		(mid 85.334469 -230.374079)
		(end 85.057996 -230.30688)
		(width 0.088646)
		(layer "F.Cu")
		(net "M_A_CPU1_SB_DQS_DN<7>")
	)
	(arc
		(start 86.922864 -230.94696)
		(mid 86.735666 -230.997103)
		(end 86.548468 -230.94696)
		(width 0.088646)
		(layer "F.Cu")
		(net "M_A_CPU1_SB_DQS_DN<7>")
	)
	(arc
		(start 84.879942 -230.24846)
		(mid 84.86801 -230.247889)
		(end 84.856066 -230.247698)
		(width 0.088646)
		(layer "F.Cu")
		(net "M_A_CPU1_SB_DQS_DN<7>")
	)
	(arc
		(start 85.97646 -230.293926)
		(mid 85.791914 -230.247725)
		(end 85.608414 -230.29799)
		(width 0.088646)
		(layer "F.Cu")
		(net "M_A_CPU1_SB_DQS_DN<7>")
	)
	(arc
		(start 85.043264 -230.298244)
		(mid 84.964473 -230.263943)
		(end 84.879942 -230.24846)
		(width 0.088646)
		(layer "F.Cu")
		(net "M_A_CPU1_SB_DQS_DN<7>")
	)
	(arc
		(start 86.548214 -230.946706)
		(mid 86.4274 -230.835385)
		(end 86.365842 -230.683054)
		(width 0.088646)
		(layer "F.Cu")
		(net "M_A_CPU1_SB_DQS_DN<7>")
	)
	(arc
		(start 87.675466 -230.622602)
		(mid 87.48307 -230.648264)
		(end 87.304118 -230.72344)
		(width 0.088646)
		(layer "F.Cu")
		(net "M_A_CPU1_SB_DQS_DN<7>")
	)
	(segment
		(start 62.139068 -218.150186)
		(end 62.147958 -218.150186)
		(width 0.1016)
		(layer "F.Cu")
		(net "M_A_CPU1_SB_DQS_DN<6>")
	)
	(segment
		(start 76.269342 -228.952298)
		(end 76.231242 -228.952298)
		(width 0.1524)
		(layer "F.Cu")
		(net "M_A_CPU1_SB_DQS_DN<6>")
	)
	(segment
		(start 59.174634 -217.878914)
		(end 59.444636 -218.148916)
		(width 0.20066)
		(layer "F.Cu")
		(net "M_A_CPU1_SB_DQS_DN<6>")
	)
	(segment
		(start 86.358984 -235.473494)
		(end 86.287356 -235.332778)
		(width 0.088646)
		(layer "F.Cu")
		(net "M_A_CPU1_SB_DQS_DN<6>")
	)
	(segment
		(start 63.031624 -217.894662)
		(end 63.674752 -218.32443)
		(width 0.20066)
		(layer "F.Cu")
		(net "M_A_CPU1_SB_DQS_DN<6>")
	)
	(segment
		(start 82.815176 -235.073952)
		(end 76.656692 -228.915468)
		(width 0.1524)
		(layer "F.Cu")
		(net "M_A_CPU1_SB_DQS_DN<6>")
	)
	(segment
		(start 64.543432 -218.566746)
		(end 65.047114 -218.566746)
		(width 0.20066)
		(layer "F.Cu")
		(net "M_A_CPU1_SB_DQS_DN<6>")
	)
	(segment
		(start 67.345306 -218.42349)
		(end 66.635884 -218.42349)
		(width 0.20066)
		(layer "F.Cu")
		(net "M_A_CPU1_SB_DQS_DN<6>")
	)
	(segment
		(start 57.503314 -218.566746)
		(end 57.989216 -218.566746)
		(width 0.20066)
		(layer "F.Cu")
		(net "M_A_CPU1_SB_DQS_DN<6>")
	)
	(segment
		(start 83.524598 -235.041948)
		(end 83.492594 -235.073952)
		(width 0.088646)
		(layer "F.Cu")
		(net "M_A_CPU1_SB_DQS_DN<6>")
	)
	(segment
		(start 83.492594 -235.073952)
		(end 83.470496 -235.073952)
		(width 0.088646)
		(layer "F.Cu")
		(net "M_A_CPU1_SB_DQS_DN<6>")
	)
	(segment
		(start 63.674752 -218.32443)
		(end 64.301116 -218.32443)
		(width 0.20066)
		(layer "F.Cu")
		(net "M_A_CPU1_SB_DQS_DN<6>")
	)
	(segment
		(start 76.231242 -228.952298)
		(end 72.998584 -228.952298)
		(width 0.20066)
		(layer "F.Cu")
		(net "M_A_CPU1_SB_DQS_DN<6>")
	)
	(segment
		(start 86.36 -235.487718)
		(end 86.360254 -235.487718)
		(width 0.088646)
		(layer "F.Cu")
		(net "M_A_CPU1_SB_DQS_DN<6>")
	)
	(segment
		(start 85.98154 -235.180124)
		(end 85.979762 -235.179108)
		(width 0.088646)
		(layer "F.Cu")
		(net "M_A_CPU1_SB_DQS_DN<6>")
	)
	(segment
		(start 83.973162 -235.131102)
		(end 83.884008 -235.041948)
		(width 0.088646)
		(layer "F.Cu")
		(net "M_A_CPU1_SB_DQS_DN<6>")
	)
	(segment
		(start 65.778634 -218.563444)
		(end 65.775332 -218.566746)
		(width 0.20066)
		(layer "F.Cu")
		(net "M_A_CPU1_SB_DQS_DN<6>")
	)
	(segment
		(start 66.296032 -218.563444)
		(end 65.778634 -218.563444)
		(width 0.20066)
		(layer "F.Cu")
		(net "M_A_CPU1_SB_DQS_DN<6>")
	)
	(segment
		(start 86.287356 -235.332778)
		(end 85.982302 -235.180378)
		(width 0.088646)
		(layer "F.Cu")
		(net "M_A_CPU1_SB_DQS_DN<6>")
	)
	(segment
		(start 86.360254 -235.487718)
		(end 86.358984 -235.473494)
		(width 0.088646)
		(layer "F.Cu")
		(net "M_A_CPU1_SB_DQS_DN<6>")
	)
	(segment
		(start 65.775332 -218.566746)
		(end 65.047114 -218.566746)
		(width 0.20066)
		(layer "F.Cu")
		(net "M_A_CPU1_SB_DQS_DN<6>")
	)
	(segment
		(start 71.2216 -222.095314)
		(end 67.694556 -218.56827)
		(width 0.20066)
		(layer "F.Cu")
		(net "M_A_CPU1_SB_DQS_DN<6>")
	)
	(segment
		(start 62.130686 -218.141804)
		(end 62.139068 -218.150186)
		(width 0.1016)
		(layer "F.Cu")
		(net "M_A_CPU1_SB_DQS_DN<6>")
	)
	(segment
		(start 85.057996 -235.190284)
		(end 85.043264 -235.181648)
		(width 0.088646)
		(layer "F.Cu")
		(net "M_A_CPU1_SB_DQS_DN<6>")
	)
	(segment
		(start 67.694556 -218.56827)
		(end 67.345306 -218.42349)
		(width 0.20066)
		(layer "F.Cu")
		(net "M_A_CPU1_SB_DQS_DN<6>")
	)
	(segment
		(start 59.822842 -218.148916)
		(end 59.829954 -218.141804)
		(width 0.1016)
		(layer "F.Cu")
		(net "M_A_CPU1_SB_DQS_DN<6>")
	)
	(segment
		(start 58.602626 -218.305634)
		(end 59.029346 -217.878914)
		(width 0.20066)
		(layer "F.Cu")
		(net "M_A_CPU1_SB_DQS_DN<6>")
	)
	(segment
		(start 62.147958 -218.150186)
		(end 62.472316 -218.150186)
		(width 0.20066)
		(layer "F.Cu")
		(net "M_A_CPU1_SB_DQS_DN<6>")
	)
	(segment
		(start 66.635884 -218.42349)
		(end 66.296032 -218.563444)
		(width 0.20066)
		(layer "F.Cu")
		(net "M_A_CPU1_SB_DQS_DN<6>")
	)
	(segment
		(start 76.306172 -228.915468)
		(end 76.269342 -228.952298)
		(width 0.1524)
		(layer "F.Cu")
		(net "M_A_CPU1_SB_DQS_DN<6>")
	)
	(segment
		(start 83.470496 -235.073952)
		(end 82.815176 -235.073952)
		(width 0.1524)
		(layer "F.Cu")
		(net "M_A_CPU1_SB_DQS_DN<6>")
	)
	(segment
		(start 58.250328 -218.305634)
		(end 58.602626 -218.305634)
		(width 0.20066)
		(layer "F.Cu")
		(net "M_A_CPU1_SB_DQS_DN<6>")
	)
	(segment
		(start 86.365842 -235.566458)
		(end 86.36 -235.487718)
		(width 0.088646)
		(layer "F.Cu")
		(net "M_A_CPU1_SB_DQS_DN<6>")
	)
	(segment
		(start 62.72784 -217.894662)
		(end 63.031624 -217.894662)
		(width 0.20066)
		(layer "F.Cu")
		(net "M_A_CPU1_SB_DQS_DN<6>")
	)
	(segment
		(start 59.444636 -218.148916)
		(end 59.822842 -218.148916)
		(width 0.20066)
		(layer "F.Cu")
		(net "M_A_CPU1_SB_DQS_DN<6>")
	)
	(segment
		(start 64.301116 -218.32443)
		(end 64.543432 -218.566746)
		(width 0.20066)
		(layer "F.Cu")
		(net "M_A_CPU1_SB_DQS_DN<6>")
	)
	(segment
		(start 83.884008 -235.041948)
		(end 83.524598 -235.041948)
		(width 0.088646)
		(layer "F.Cu")
		(net "M_A_CPU1_SB_DQS_DN<6>")
	)
	(segment
		(start 85.608414 -235.181394)
		(end 85.608668 -235.181648)
		(width 0.088646)
		(layer "F.Cu")
		(net "M_A_CPU1_SB_DQS_DN<6>")
	)
	(segment
		(start 57.989216 -218.566746)
		(end 58.250328 -218.305634)
		(width 0.20066)
		(layer "F.Cu")
		(net "M_A_CPU1_SB_DQS_DN<6>")
	)
	(segment
		(start 59.829954 -218.141804)
		(end 62.130686 -218.141804)
		(width 0.1016)
		(layer "F.Cu")
		(net "M_A_CPU1_SB_DQS_DN<6>")
	)
	(segment
		(start 85.982302 -235.180378)
		(end 85.98154 -235.180124)
		(width 0.088646)
		(layer "F.Cu")
		(net "M_A_CPU1_SB_DQS_DN<6>")
	)
	(segment
		(start 62.472316 -218.150186)
		(end 62.72784 -217.894662)
		(width 0.20066)
		(layer "F.Cu")
		(net "M_A_CPU1_SB_DQS_DN<6>")
	)
	(segment
		(start 87.304118 -235.606844)
		(end 86.922864 -235.830364)
		(width 0.088646)
		(layer "F.Cu")
		(net "M_A_CPU1_SB_DQS_DN<6>")
	)
	(segment
		(start 71.2216 -227.175314)
		(end 71.2216 -222.095314)
		(width 0.20066)
		(layer "F.Cu")
		(net "M_A_CPU1_SB_DQS_DN<6>")
	)
	(segment
		(start 84.85632 -235.131102)
		(end 83.973162 -235.131102)
		(width 0.088646)
		(layer "F.Cu")
		(net "M_A_CPU1_SB_DQS_DN<6>")
	)
	(segment
		(start 59.029346 -217.878914)
		(end 59.174634 -217.878914)
		(width 0.20066)
		(layer "F.Cu")
		(net "M_A_CPU1_SB_DQS_DN<6>")
	)
	(segment
		(start 76.656692 -228.915468)
		(end 76.306172 -228.915468)
		(width 0.1524)
		(layer "F.Cu")
		(net "M_A_CPU1_SB_DQS_DN<6>")
	)
	(segment
		(start 85.979762 -235.179108)
		(end 85.97646 -235.17733)
		(width 0.088646)
		(layer "F.Cu")
		(net "M_A_CPU1_SB_DQS_DN<6>")
	)
	(segment
		(start 72.998584 -228.952298)
		(end 71.2216 -227.175314)
		(width 0.20066)
		(layer "F.Cu")
		(net "M_A_CPU1_SB_DQS_DN<6>")
	)
	(arc
		(start 85.043264 -235.181648)
		(mid 84.964473 -235.147347)
		(end 84.879942 -235.131864)
		(width 0.088646)
		(layer "F.Cu")
		(net "M_A_CPU1_SB_DQS_DN<6>")
	)
	(arc
		(start 87.675466 -235.506006)
		(mid 87.48307 -235.531668)
		(end 87.304118 -235.606844)
		(width 0.088646)
		(layer "F.Cu")
		(net "M_A_CPU1_SB_DQS_DN<6>")
	)
	(arc
		(start 86.922864 -235.830364)
		(mid 86.735666 -235.880507)
		(end 86.548468 -235.830364)
		(width 0.088646)
		(layer "F.Cu")
		(net "M_A_CPU1_SB_DQS_DN<6>")
	)
	(arc
		(start 85.97646 -235.17733)
		(mid 85.791914 -235.131129)
		(end 85.608414 -235.181394)
		(width 0.088646)
		(layer "F.Cu")
		(net "M_A_CPU1_SB_DQS_DN<6>")
	)
	(arc
		(start 84.879942 -235.131864)
		(mid 84.868137 -235.131297)
		(end 84.85632 -235.131102)
		(width 0.088646)
		(layer "F.Cu")
		(net "M_A_CPU1_SB_DQS_DN<6>")
	)
	(arc
		(start 86.548468 -235.830364)
		(mid 86.427501 -235.718932)
		(end 86.365842 -235.566458)
		(width 0.088646)
		(layer "F.Cu")
		(net "M_A_CPU1_SB_DQS_DN<6>")
	)
	(arc
		(start 85.608668 -235.181648)
		(mid 85.598063 -235.187605)
		(end 85.587332 -235.193332)
		(width 0.088646)
		(layer "F.Cu")
		(net "M_A_CPU1_SB_DQS_DN<6>")
	)
	(arc
		(start 85.587332 -235.193332)
		(mid 85.322275 -235.25762)
		(end 85.057996 -235.190284)
		(width 0.088646)
		(layer "F.Cu")
		(net "M_A_CPU1_SB_DQS_DN<6>")
	)
	(segment
		(start 59.822842 -227.514658)
		(end 59.645296 -227.514658)
		(width 0.20066)
		(layer "F.Cu")
		(net "M_A_CPU1_SB_DQS_DN<5>")
	)
	(segment
		(start 90.024712 -237.411768)
		(end 90.024966 -237.411514)
		(width 0.20066)
		(layer "F.Cu")
		(net "M_A_CPU1_SB_DQS_DN<5>")
	)
	(segment
		(start 65.047114 -227.91674)
		(end 64.543432 -227.91674)
		(width 0.20066)
		(layer "F.Cu")
		(net "M_A_CPU1_SB_DQS_DN<5>")
	)
	(segment
		(start 63.68923 -227.655628)
		(end 63.090298 -227.255578)
		(width 0.20066)
		(layer "F.Cu")
		(net "M_A_CPU1_SB_DQS_DN<5>")
	)
	(segment
		(start 62.549786 -227.255578)
		(end 62.313566 -227.491798)
		(width 0.20066)
		(layer "F.Cu")
		(net "M_A_CPU1_SB_DQS_DN<5>")
	)
	(segment
		(start 59.367166 -227.236528)
		(end 59.128406 -227.236528)
		(width 0.20066)
		(layer "F.Cu")
		(net "M_A_CPU1_SB_DQS_DN<5>")
	)
	(segment
		(start 62.313566 -227.491798)
		(end 62.147958 -227.491798)
		(width 0.20066)
		(layer "F.Cu")
		(net "M_A_CPU1_SB_DQS_DN<5>")
	)
	(segment
		(start 57.989216 -227.91674)
		(end 57.503314 -227.91674)
		(width 0.20066)
		(layer "F.Cu")
		(net "M_A_CPU1_SB_DQS_DN<5>")
	)
	(segment
		(start 64.28232 -227.655628)
		(end 63.68923 -227.655628)
		(width 0.20066)
		(layer "F.Cu")
		(net "M_A_CPU1_SB_DQS_DN<5>")
	)
	(segment
		(start 58.709306 -227.655628)
		(end 58.250328 -227.655628)
		(width 0.20066)
		(layer "F.Cu")
		(net "M_A_CPU1_SB_DQS_DN<5>")
	)
	(segment
		(start 64.543432 -227.91674)
		(end 64.28232 -227.655628)
		(width 0.20066)
		(layer "F.Cu")
		(net "M_A_CPU1_SB_DQS_DN<5>")
	)
	(segment
		(start 59.845702 -227.491798)
		(end 59.822842 -227.514658)
		(width 0.101854)
		(layer "F.Cu")
		(net "M_A_CPU1_SB_DQS_DN<5>")
	)
	(segment
		(start 59.645296 -227.514658)
		(end 59.367166 -227.236528)
		(width 0.20066)
		(layer "F.Cu")
		(net "M_A_CPU1_SB_DQS_DN<5>")
	)
	(segment
		(start 66.152014 -227.91674)
		(end 65.047114 -227.91674)
		(width 0.20066)
		(layer "F.Cu")
		(net "M_A_CPU1_SB_DQS_DN<5>")
	)
	(segment
		(start 63.090298 -227.255578)
		(end 62.549786 -227.255578)
		(width 0.20066)
		(layer "F.Cu")
		(net "M_A_CPU1_SB_DQS_DN<5>")
	)
	(segment
		(start 60.164218 -227.491798)
		(end 59.845702 -227.491798)
		(width 0.101854)
		(layer "F.Cu")
		(net "M_A_CPU1_SB_DQS_DN<5>")
	)
	(segment
		(start 59.128406 -227.236528)
		(end 58.709306 -227.655628)
		(width 0.20066)
		(layer "F.Cu")
		(net "M_A_CPU1_SB_DQS_DN<5>")
	)
	(segment
		(start 58.250328 -227.655628)
		(end 57.989216 -227.91674)
		(width 0.20066)
		(layer "F.Cu")
		(net "M_A_CPU1_SB_DQS_DN<5>")
	)
	(segment
		(start 62.147958 -227.491798)
		(end 60.164218 -227.491798)
		(width 0.1016)
		(layer "F.Cu")
		(net "M_A_CPU1_SB_DQS_DN<5>")
	)
	(segment
		(start 90.024712 -237.947454)
		(end 90.024712 -237.411768)
		(width 0.20066)
		(layer "F.Cu")
		(net "M_A_CPU1_SB_DQS_DN<5>")
	)
	(segment
		(start 90.221054 -237.092236)
		(end 90.212164 -237.08741)
		(width 0.088646)
		(layer "In2.Cu")
		(net "M_A_CPU1_SB_DQS_DN<5>")
	)
	(segment
		(start 69.679566 -227.779072)
		(end 69.130926 -227.779072)
		(width 0.18288)
		(layer "In2.Cu")
		(net "M_A_CPU1_SB_DQS_DN<5>")
	)
	(segment
		(start 82.85226 -237.168182)
		(end 82.79257 -237.227872)
		(width 0.088646)
		(layer "In2.Cu")
		(net "M_A_CPU1_SB_DQS_DN<5>")
	)
	(segment
		(start 82.79257 -237.227872)
		(end 80.169004 -237.227872)
		(width 0.18288)
		(layer "In2.Cu")
		(net "M_A_CPU1_SB_DQS_DN<5>")
	)
	(segment
		(start 85.138514 -237.08741)
		(end 85.123782 -237.096046)
		(width 0.088646)
		(layer "In2.Cu")
		(net "M_A_CPU1_SB_DQS_DN<5>")
	)
	(segment
		(start 87.958168 -237.08741)
		(end 87.947754 -237.093506)
		(width 0.088646)
		(layer "In2.Cu")
		(net "M_A_CPU1_SB_DQS_DN<5>")
	)
	(segment
		(start 90.337894 -237.411514)
		(end 90.395044 -237.354364)
		(width 0.088646)
		(layer "In2.Cu")
		(net "M_A_CPU1_SB_DQS_DN<5>")
	)
	(segment
		(start 80.169004 -237.227872)
		(end 78.626462 -235.68533)
		(width 0.18288)
		(layer "In2.Cu")
		(net "M_A_CPU1_SB_DQS_DN<5>")
	)
	(segment
		(start 84.210398 -237.080044)
		(end 84.209382 -237.080298)
		(width 0.088646)
		(layer "In2.Cu")
		(net "M_A_CPU1_SB_DQS_DN<5>")
	)
	(segment
		(start 78.45044 -235.68533)
		(end 78.062074 -235.296964)
		(width 0.18288)
		(layer "In2.Cu")
		(net "M_A_CPU1_SB_DQS_DN<5>")
	)
	(segment
		(start 86.078568 -237.08741)
		(end 86.068154 -237.093506)
		(width 0.088646)
		(layer "In2.Cu")
		(net "M_A_CPU1_SB_DQS_DN<5>")
	)
	(segment
		(start 70.595744 -227.654612)
		(end 69.804026 -227.654612)
		(width 0.18288)
		(layer "In2.Cu")
		(net "M_A_CPU1_SB_DQS_DN<5>")
	)
	(segment
		(start 68.457826 -227.654612)
		(end 68.333366 -227.779072)
		(width 0.18288)
		(layer "In2.Cu")
		(net "M_A_CPU1_SB_DQS_DN<5>")
	)
	(segment
		(start 67.660266 -227.654612)
		(end 66.414142 -227.654612)
		(width 0.18288)
		(layer "In2.Cu")
		(net "M_A_CPU1_SB_DQS_DN<5>")
	)
	(segment
		(start 78.062074 -235.120942)
		(end 70.595744 -227.654612)
		(width 0.18288)
		(layer "In2.Cu")
		(net "M_A_CPU1_SB_DQS_DN<5>")
	)
	(segment
		(start 89.287096 -237.096046)
		(end 89.272364 -237.08741)
		(width 0.088646)
		(layer "In2.Cu")
		(net "M_A_CPU1_SB_DQS_DN<5>")
	)
	(segment
		(start 67.784726 -227.779072)
		(end 67.660266 -227.654612)
		(width 0.18288)
		(layer "In2.Cu")
		(net "M_A_CPU1_SB_DQS_DN<5>")
	)
	(segment
		(start 68.333366 -227.779072)
		(end 67.784726 -227.779072)
		(width 0.18288)
		(layer "In2.Cu")
		(net "M_A_CPU1_SB_DQS_DN<5>")
	)
	(segment
		(start 69.130926 -227.779072)
		(end 69.006466 -227.654612)
		(width 0.18288)
		(layer "In2.Cu")
		(net "M_A_CPU1_SB_DQS_DN<5>")
	)
	(segment
		(start 78.626462 -235.68533)
		(end 78.45044 -235.68533)
		(width 0.18288)
		(layer "In2.Cu")
		(net "M_A_CPU1_SB_DQS_DN<5>")
	)
	(segment
		(start 69.006466 -227.654612)
		(end 68.457826 -227.654612)
		(width 0.18288)
		(layer "In2.Cu")
		(net "M_A_CPU1_SB_DQS_DN<5>")
	)
	(segment
		(start 66.414142 -227.654612)
		(end 66.152014 -227.91674)
		(width 0.18288)
		(layer "In2.Cu")
		(net "M_A_CPU1_SB_DQS_DN<5>")
	)
	(segment
		(start 78.062074 -235.296964)
		(end 78.062074 -235.120942)
		(width 0.18288)
		(layer "In2.Cu")
		(net "M_A_CPU1_SB_DQS_DN<5>")
	)
	(segment
		(start 69.804026 -227.654612)
		(end 69.679566 -227.779072)
		(width 0.18288)
		(layer "In2.Cu")
		(net "M_A_CPU1_SB_DQS_DN<5>")
	)
	(segment
		(start 87.018114 -237.08741)
		(end 87.0077 -237.093506)
		(width 0.088646)
		(layer "In2.Cu")
		(net "M_A_CPU1_SB_DQS_DN<5>")
	)
	(segment
		(start 90.024966 -237.411514)
		(end 90.337894 -237.411514)
		(width 0.088646)
		(layer "In2.Cu")
		(net "M_A_CPU1_SB_DQS_DN<5>")
	)
	(segment
		(start 83.855306 -237.168182)
		(end 82.85226 -237.168182)
		(width 0.088646)
		(layer "In2.Cu")
		(net "M_A_CPU1_SB_DQS_DN<5>")
	)
	(arc
		(start 90.212164 -237.08741)
		(mid 90.024966 -237.037233)
		(end 89.837768 -237.08741)
		(width 0.088646)
		(layer "In2.Cu")
		(net "M_A_CPU1_SB_DQS_DN<5>")
	)
	(arc
		(start 85.51291 -237.08741)
		(mid 85.325712 -237.037267)
		(end 85.138514 -237.08741)
		(width 0.088646)
		(layer "In2.Cu")
		(net "M_A_CPU1_SB_DQS_DN<5>")
	)
	(arc
		(start 86.452964 -237.08741)
		(mid 86.265766 -237.037267)
		(end 86.078568 -237.08741)
		(width 0.088646)
		(layer "In2.Cu")
		(net "M_A_CPU1_SB_DQS_DN<5>")
	)
	(arc
		(start 87.39251 -237.08741)
		(mid 87.205312 -237.037267)
		(end 87.018114 -237.08741)
		(width 0.088646)
		(layer "In2.Cu")
		(net "M_A_CPU1_SB_DQS_DN<5>")
	)
	(arc
		(start 88.897968 -237.08741)
		(mid 88.615266 -237.163186)
		(end 88.332564 -237.08741)
		(width 0.088646)
		(layer "In2.Cu")
		(net "M_A_CPU1_SB_DQS_DN<5>")
	)
	(arc
		(start 87.947754 -237.093506)
		(mid 87.669322 -237.163352)
		(end 87.39251 -237.08741)
		(width 0.088646)
		(layer "In2.Cu")
		(net "M_A_CPU1_SB_DQS_DN<5>")
	)
	(arc
		(start 84.209382 -237.080298)
		(mid 84.037728 -237.145923)
		(end 83.855306 -237.168182)
		(width 0.088646)
		(layer "In2.Cu")
		(net "M_A_CPU1_SB_DQS_DN<5>")
	)
	(arc
		(start 84.57311 -237.08741)
		(mid 84.451226 -237.042671)
		(end 84.321396 -237.042198)
		(width 0.088646)
		(layer "In2.Cu")
		(net "M_A_CPU1_SB_DQS_DN<5>")
	)
	(arc
		(start 86.068154 -237.093506)
		(mid 85.789722 -237.163352)
		(end 85.51291 -237.08741)
		(width 0.088646)
		(layer "In2.Cu")
		(net "M_A_CPU1_SB_DQS_DN<5>")
	)
	(arc
		(start 85.123782 -237.096046)
		(mid 84.847307 -237.163366)
		(end 84.57311 -237.08741)
		(width 0.088646)
		(layer "In2.Cu")
		(net "M_A_CPU1_SB_DQS_DN<5>")
	)
	(arc
		(start 84.321396 -237.042198)
		(mid 84.264406 -237.056749)
		(end 84.210398 -237.080044)
		(width 0.088646)
		(layer "In2.Cu")
		(net "M_A_CPU1_SB_DQS_DN<5>")
	)
	(arc
		(start 90.395044 -237.354364)
		(mid 90.336925 -237.204123)
		(end 90.221054 -237.092236)
		(width 0.088646)
		(layer "In2.Cu")
		(net "M_A_CPU1_SB_DQS_DN<5>")
	)
	(arc
		(start 89.837768 -237.08741)
		(mid 89.563569 -237.163245)
		(end 89.287096 -237.096046)
		(width 0.088646)
		(layer "In2.Cu")
		(net "M_A_CPU1_SB_DQS_DN<5>")
	)
	(arc
		(start 89.272364 -237.08741)
		(mid 89.085166 -237.037233)
		(end 88.897968 -237.08741)
		(width 0.088646)
		(layer "In2.Cu")
		(net "M_A_CPU1_SB_DQS_DN<5>")
	)
	(arc
		(start 88.332564 -237.08741)
		(mid 88.145366 -237.037233)
		(end 87.958168 -237.08741)
		(width 0.088646)
		(layer "In2.Cu")
		(net "M_A_CPU1_SB_DQS_DN<5>")
	)
	(arc
		(start 87.0077 -237.093506)
		(mid 86.729522 -237.163229)
		(end 86.452964 -237.08741)
		(width 0.088646)
		(layer "In2.Cu")
		(net "M_A_CPU1_SB_DQS_DN<5>")
	)
	(segment
		(start 85.98154 -240.063274)
		(end 85.979762 -240.062258)
		(width 0.088646)
		(layer "F.Cu")
		(net "M_A_CPU1_SB_DQS_DN<4>")
	)
	(segment
		(start 75.375262 -237.848648)
		(end 75.174348 -237.647734)
		(width 0.20066)
		(layer "F.Cu")
		(net "M_A_CPU1_SB_DQS_DN<4>")
	)
	(segment
		(start 65.318132 -237.266734)
		(end 65.047114 -237.266734)
		(width 0.20066)
		(layer "F.Cu")
		(net "M_A_CPU1_SB_DQS_DN<4>")
	)
	(segment
		(start 68.010024 -237.237524)
		(end 65.974722 -237.237524)
		(width 0.20066)
		(layer "F.Cu")
		(net "M_A_CPU1_SB_DQS_DN<4>")
	)
	(segment
		(start 65.945766 -237.26648)
		(end 65.318386 -237.26648)
		(width 0.20066)
		(layer "F.Cu")
		(net "M_A_CPU1_SB_DQS_DN<4>")
	)
	(segment
		(start 75.174348 -237.647734)
		(end 74.858118 -237.647734)
		(width 0.20066)
		(layer "F.Cu")
		(net "M_A_CPU1_SB_DQS_DN<4>")
	)
	(segment
		(start 81.019396 -239.34166)
		(end 80.981296 -239.34166)
		(width 0.1524)
		(layer "F.Cu")
		(net "M_A_CPU1_SB_DQS_DN<4>")
	)
	(segment
		(start 57.989216 -237.266734)
		(end 58.250328 -237.005622)
		(width 0.20066)
		(layer "F.Cu")
		(net "M_A_CPU1_SB_DQS_DN<4>")
	)
	(segment
		(start 74.358754 -238.551466)
		(end 73.810368 -238.551466)
		(width 0.20066)
		(layer "F.Cu")
		(net "M_A_CPU1_SB_DQS_DN<4>")
	)
	(segment
		(start 58.709306 -237.005622)
		(end 59.088782 -236.626146)
		(width 0.20066)
		(layer "F.Cu")
		(net "M_A_CPU1_SB_DQS_DN<4>")
	)
	(segment
		(start 62.404752 -236.841792)
		(end 62.51829 -236.841792)
		(width 0.20066)
		(layer "F.Cu")
		(net "M_A_CPU1_SB_DQS_DN<4>")
	)
	(segment
		(start 73.810368 -238.551466)
		(end 71.745602 -237.696248)
		(width 0.20066)
		(layer "F.Cu")
		(net "M_A_CPU1_SB_DQS_DN<4>")
	)
	(segment
		(start 81.056226 -239.30483)
		(end 81.019396 -239.34166)
		(width 0.1524)
		(layer "F.Cu")
		(net "M_A_CPU1_SB_DQS_DN<4>")
	)
	(segment
		(start 83.581748 -239.80902)
		(end 83.424522 -239.80902)
		(width 0.088646)
		(layer "F.Cu")
		(net "M_A_CPU1_SB_DQS_DN<4>")
	)
	(segment
		(start 75.698096 -239.34166)
		(end 75.375262 -239.018826)
		(width 0.20066)
		(layer "F.Cu")
		(net "M_A_CPU1_SB_DQS_DN<4>")
	)
	(segment
		(start 82.87512 -239.30483)
		(end 81.056226 -239.30483)
		(width 0.1524)
		(layer "F.Cu")
		(net "M_A_CPU1_SB_DQS_DN<4>")
	)
	(segment
		(start 83.424522 -239.80902)
		(end 83.203288 -239.587786)
		(width 0.088646)
		(layer "F.Cu")
		(net "M_A_CPU1_SB_DQS_DN<4>")
	)
	(segment
		(start 75.375262 -239.018826)
		(end 75.375262 -237.848648)
		(width 0.20066)
		(layer "F.Cu")
		(net "M_A_CPU1_SB_DQS_DN<4>")
	)
	(segment
		(start 83.158076 -239.587786)
		(end 83.142582 -239.572292)
		(width 0.088646)
		(layer "F.Cu")
		(net "M_A_CPU1_SB_DQS_DN<4>")
	)
	(segment
		(start 86.358984 -240.356644)
		(end 86.287356 -240.215928)
		(width 0.088646)
		(layer "F.Cu")
		(net "M_A_CPU1_SB_DQS_DN<4>")
	)
	(segment
		(start 85.057996 -240.073434)
		(end 85.043264 -240.064798)
		(width 0.088646)
		(layer "F.Cu")
		(net "M_A_CPU1_SB_DQS_DN<4>")
	)
	(segment
		(start 59.69889 -236.841792)
		(end 62.404752 -236.841792)
		(width 0.1016)
		(layer "F.Cu")
		(net "M_A_CPU1_SB_DQS_DN<4>")
	)
	(segment
		(start 80.981296 -239.34166)
		(end 75.698096 -239.34166)
		(width 0.20066)
		(layer "F.Cu")
		(net "M_A_CPU1_SB_DQS_DN<4>")
	)
	(segment
		(start 83.7057 -239.932972)
		(end 83.581748 -239.80902)
		(width 0.088646)
		(layer "F.Cu")
		(net "M_A_CPU1_SB_DQS_DN<4>")
	)
	(segment
		(start 85.982302 -240.063528)
		(end 85.98154 -240.063274)
		(width 0.088646)
		(layer "F.Cu")
		(net "M_A_CPU1_SB_DQS_DN<4>")
	)
	(segment
		(start 64.28232 -237.005622)
		(end 64.543432 -237.266734)
		(width 0.20066)
		(layer "F.Cu")
		(net "M_A_CPU1_SB_DQS_DN<4>")
	)
	(segment
		(start 74.657204 -237.848648)
		(end 74.657204 -238.253016)
		(width 0.20066)
		(layer "F.Cu")
		(net "M_A_CPU1_SB_DQS_DN<4>")
	)
	(segment
		(start 63.13424 -236.582966)
		(end 63.7667 -237.005622)
		(width 0.20066)
		(layer "F.Cu")
		(net "M_A_CPU1_SB_DQS_DN<4>")
	)
	(segment
		(start 83.203288 -239.587786)
		(end 83.158076 -239.587786)
		(width 0.088646)
		(layer "F.Cu")
		(net "M_A_CPU1_SB_DQS_DN<4>")
	)
	(segment
		(start 74.657204 -238.253016)
		(end 74.358754 -238.551466)
		(width 0.20066)
		(layer "F.Cu")
		(net "M_A_CPU1_SB_DQS_DN<4>")
	)
	(segment
		(start 86.361016 -240.389156)
		(end 86.358984 -240.356644)
		(width 0.088646)
		(layer "F.Cu")
		(net "M_A_CPU1_SB_DQS_DN<4>")
	)
	(segment
		(start 84.856066 -240.014252)
		(end 84.113116 -240.014252)
		(width 0.088646)
		(layer "F.Cu")
		(net "M_A_CPU1_SB_DQS_DN<4>")
	)
	(segment
		(start 62.51829 -236.841792)
		(end 62.777116 -236.582966)
		(width 0.20066)
		(layer "F.Cu")
		(net "M_A_CPU1_SB_DQS_DN<4>")
	)
	(segment
		(start 74.858118 -237.647734)
		(end 74.657204 -237.848648)
		(width 0.20066)
		(layer "F.Cu")
		(net "M_A_CPU1_SB_DQS_DN<4>")
	)
	(segment
		(start 58.250328 -237.005622)
		(end 58.709306 -237.005622)
		(width 0.20066)
		(layer "F.Cu")
		(net "M_A_CPU1_SB_DQS_DN<4>")
	)
	(segment
		(start 59.088782 -236.626146)
		(end 59.202828 -236.578902)
		(width 0.20066)
		(layer "F.Cu")
		(net "M_A_CPU1_SB_DQS_DN<4>")
	)
	(segment
		(start 64.543432 -237.266734)
		(end 65.047114 -237.266734)
		(width 0.20066)
		(layer "F.Cu")
		(net "M_A_CPU1_SB_DQS_DN<4>")
	)
	(segment
		(start 65.974722 -237.237524)
		(end 65.945766 -237.26648)
		(width 0.20066)
		(layer "F.Cu")
		(net "M_A_CPU1_SB_DQS_DN<4>")
	)
	(segment
		(start 71.745602 -237.696248)
		(end 68.468748 -237.696248)
		(width 0.20066)
		(layer "F.Cu")
		(net "M_A_CPU1_SB_DQS_DN<4>")
	)
	(segment
		(start 57.503314 -237.266734)
		(end 57.989216 -237.266734)
		(width 0.20066)
		(layer "F.Cu")
		(net "M_A_CPU1_SB_DQS_DN<4>")
	)
	(segment
		(start 85.608414 -240.064544)
		(end 85.608668 -240.064798)
		(width 0.088646)
		(layer "F.Cu")
		(net "M_A_CPU1_SB_DQS_DN<4>")
	)
	(segment
		(start 59.366658 -236.578902)
		(end 59.629548 -236.841792)
		(width 0.20066)
		(layer "F.Cu")
		(net "M_A_CPU1_SB_DQS_DN<4>")
	)
	(segment
		(start 87.304118 -240.489994)
		(end 86.922864 -240.713514)
		(width 0.088646)
		(layer "F.Cu")
		(net "M_A_CPU1_SB_DQS_DN<4>")
	)
	(segment
		(start 86.287356 -240.215928)
		(end 85.982302 -240.063528)
		(width 0.088646)
		(layer "F.Cu")
		(net "M_A_CPU1_SB_DQS_DN<4>")
	)
	(segment
		(start 59.629548 -236.841792)
		(end 59.69889 -236.841792)
		(width 0.20066)
		(layer "F.Cu")
		(net "M_A_CPU1_SB_DQS_DN<4>")
	)
	(segment
		(start 63.7667 -237.005622)
		(end 64.28232 -237.005622)
		(width 0.20066)
		(layer "F.Cu")
		(net "M_A_CPU1_SB_DQS_DN<4>")
	)
	(segment
		(start 65.318386 -237.26648)
		(end 65.318132 -237.266734)
		(width 0.20066)
		(layer "F.Cu")
		(net "M_A_CPU1_SB_DQS_DN<4>")
	)
	(segment
		(start 86.548468 -240.713514)
		(end 86.548468 -240.71326)
		(width 0.088646)
		(layer "F.Cu")
		(net "M_A_CPU1_SB_DQS_DN<4>")
	)
	(segment
		(start 85.979762 -240.062258)
		(end 85.97646 -240.06048)
		(width 0.088646)
		(layer "F.Cu")
		(net "M_A_CPU1_SB_DQS_DN<4>")
	)
	(segment
		(start 59.202828 -236.578902)
		(end 59.366658 -236.578902)
		(width 0.20066)
		(layer "F.Cu")
		(net "M_A_CPU1_SB_DQS_DN<4>")
	)
	(segment
		(start 62.777116 -236.582966)
		(end 63.13424 -236.582966)
		(width 0.20066)
		(layer "F.Cu")
		(net "M_A_CPU1_SB_DQS_DN<4>")
	)
	(segment
		(start 68.468748 -237.696248)
		(end 68.010024 -237.237524)
		(width 0.20066)
		(layer "F.Cu")
		(net "M_A_CPU1_SB_DQS_DN<4>")
	)
	(segment
		(start 83.142582 -239.572292)
		(end 82.87512 -239.30483)
		(width 0.1524)
		(layer "F.Cu")
		(net "M_A_CPU1_SB_DQS_DN<4>")
	)
	(arc
		(start 86.548468 -240.71326)
		(mid 86.411328 -240.576321)
		(end 86.361016 -240.389156)
		(width 0.088646)
		(layer "F.Cu")
		(net "M_A_CPU1_SB_DQS_DN<4>")
	)
	(arc
		(start 85.043264 -240.064798)
		(mid 84.952992 -240.027199)
		(end 84.856066 -240.014252)
		(width 0.088646)
		(layer "F.Cu")
		(net "M_A_CPU1_SB_DQS_DN<4>")
	)
	(arc
		(start 86.922864 -240.713514)
		(mid 86.735666 -240.763657)
		(end 86.548468 -240.713514)
		(width 0.088646)
		(layer "F.Cu")
		(net "M_A_CPU1_SB_DQS_DN<4>")
	)
	(arc
		(start 87.675466 -240.389156)
		(mid 87.48307 -240.414818)
		(end 87.304118 -240.489994)
		(width 0.088646)
		(layer "F.Cu")
		(net "M_A_CPU1_SB_DQS_DN<4>")
	)
	(arc
		(start 84.113116 -240.014252)
		(mid 83.905404 -239.993684)
		(end 83.7057 -239.932972)
		(width 0.088646)
		(layer "F.Cu")
		(net "M_A_CPU1_SB_DQS_DN<4>")
	)
	(arc
		(start 85.608668 -240.064798)
		(mid 85.334469 -240.140633)
		(end 85.057996 -240.073434)
		(width 0.088646)
		(layer "F.Cu")
		(net "M_A_CPU1_SB_DQS_DN<4>")
	)
	(arc
		(start 85.97646 -240.06048)
		(mid 85.791914 -240.014279)
		(end 85.608414 -240.064544)
		(width 0.088646)
		(layer "F.Cu")
		(net "M_A_CPU1_SB_DQS_DN<4>")
	)
	(segment
		(start 83.714336 -214.706708)
		(end 83.714336 -214.098378)
		(width 0.1524)
		(layer "F.Cu")
		(net "M_A_CPU1_SB_DQS_DN<3>")
	)
	(segment
		(start 55.73014 -200.560178)
		(end 56.003698 -200.28662)
		(width 0.20066)
		(layer "F.Cu")
		(net "M_A_CPU1_SB_DQS_DN<3>")
	)
	(segment
		(start 60.357766 -199.866758)
		(end 60.947046 -199.866758)
		(width 0.20066)
		(layer "F.Cu")
		(net "M_A_CPU1_SB_DQS_DN<3>")
	)
	(segment
		(start 63.439802 -200.607676)
		(end 63.177674 -200.607676)
		(width 0.20066)
		(layer "F.Cu")
		(net "M_A_CPU1_SB_DQS_DN<3>")
	)
	(segment
		(start 53.403246 -199.866758)
		(end 53.951886 -199.866758)
		(width 0.20066)
		(layer "F.Cu")
		(net "M_A_CPU1_SB_DQS_DN<3>")
	)
	(segment
		(start 56.37911 -200.28662)
		(end 56.38419 -200.2917)
		(width 0.1016)
		(layer "F.Cu")
		(net "M_A_CPU1_SB_DQS_DN<3>")
	)
	(segment
		(start 83.714336 -214.098378)
		(end 83.760056 -214.052658)
		(width 0.1524)
		(layer "F.Cu")
		(net "M_A_CPU1_SB_DQS_DN<3>")
	)
	(segment
		(start 80.594454 -207.03794)
		(end 80.169004 -206.61249)
		(width 0.20066)
		(layer "F.Cu")
		(net "M_A_CPU1_SB_DQS_DN<3>")
	)
	(segment
		(start 59.27598 -200.559416)
		(end 59.400186 -200.559416)
		(width 0.20066)
		(layer "F.Cu")
		(net "M_A_CPU1_SB_DQS_DN<3>")
	)
	(segment
		(start 84.856066 -220.855794)
		(end 84.766404 -220.945456)
		(width 0.088646)
		(layer "F.Cu")
		(net "M_A_CPU1_SB_DQS_DN<3>")
	)
	(segment
		(start 59.400186 -200.559416)
		(end 59.852306 -200.107296)
		(width 0.20066)
		(layer "F.Cu")
		(net "M_A_CPU1_SB_DQS_DN<3>")
	)
	(segment
		(start 80.169004 -206.61249)
		(end 80.169004 -206.436468)
		(width 0.20066)
		(layer "F.Cu")
		(net "M_A_CPU1_SB_DQS_DN<3>")
	)
	(segment
		(start 63.177674 -200.607676)
		(end 61.994288 -200.117456)
		(width 0.20066)
		(layer "F.Cu")
		(net "M_A_CPU1_SB_DQS_DN<3>")
	)
	(segment
		(start 81.797906 -208.06537)
		(end 81.621884 -208.06537)
		(width 0.20066)
		(layer "F.Cu")
		(net "M_A_CPU1_SB_DQS_DN<3>")
	)
	(segment
		(start 81.621884 -208.06537)
		(end 81.196434 -207.63992)
		(width 0.20066)
		(layer "F.Cu")
		(net "M_A_CPU1_SB_DQS_DN<3>")
	)
	(segment
		(start 59.852306 -200.107296)
		(end 60.117228 -200.107296)
		(width 0.20066)
		(layer "F.Cu")
		(net "M_A_CPU1_SB_DQS_DN<3>")
	)
	(segment
		(start 79.743046 -206.01051)
		(end 79.567024 -206.01051)
		(width 0.20066)
		(layer "F.Cu")
		(net "M_A_CPU1_SB_DQS_DN<3>")
	)
	(segment
		(start 63.977012 -200.274682)
		(end 63.587884 -200.274682)
		(width 0.20066)
		(layer "F.Cu")
		(net "M_A_CPU1_SB_DQS_DN<3>")
	)
	(segment
		(start 63.587884 -200.274682)
		(end 63.503048 -200.359518)
		(width 0.20066)
		(layer "F.Cu")
		(net "M_A_CPU1_SB_DQS_DN<3>")
	)
	(segment
		(start 84.766404 -220.945456)
		(end 84.590128 -220.945456)
		(width 0.088646)
		(layer "F.Cu")
		(net "M_A_CPU1_SB_DQS_DN<3>")
	)
	(segment
		(start 84.590128 -220.945456)
		(end 84.473796 -220.829124)
		(width 0.088646)
		(layer "F.Cu")
		(net "M_A_CPU1_SB_DQS_DN<3>")
	)
	(segment
		(start 64.006476 -200.2917)
		(end 63.989458 -200.274682)
		(width 0.1016)
		(layer "F.Cu")
		(net "M_A_CPU1_SB_DQS_DN<3>")
	)
	(segment
		(start 82.22361 -208.667096)
		(end 82.22361 -208.491074)
		(width 0.20066)
		(layer "F.Cu")
		(net "M_A_CPU1_SB_DQS_DN<3>")
	)
	(segment
		(start 83.549998 -219.846652)
		(end 83.549998 -219.80144)
		(width 0.088646)
		(layer "F.Cu")
		(net "M_A_CPU1_SB_DQS_DN<3>")
	)
	(segment
		(start 53.951886 -199.866758)
		(end 54.22265 -200.137522)
		(width 0.20066)
		(layer "F.Cu")
		(net "M_A_CPU1_SB_DQS_DN<3>")
	)
	(segment
		(start 61.439806 -199.866758)
		(end 60.947046 -199.866758)
		(width 0.20066)
		(layer "F.Cu")
		(net "M_A_CPU1_SB_DQS_DN<3>")
	)
	(segment
		(start 83.534504 -219.785946)
		(end 82.899504 -219.150946)
		(width 0.1524)
		(layer "F.Cu")
		(net "M_A_CPU1_SB_DQS_DN<3>")
	)
	(segment
		(start 84.473796 -220.829124)
		(end 84.432394 -220.728794)
		(width 0.088646)
		(layer "F.Cu")
		(net "M_A_CPU1_SB_DQS_DN<3>")
	)
	(segment
		(start 82.649568 -209.093054)
		(end 82.22361 -208.667096)
		(width 0.20066)
		(layer "F.Cu")
		(net "M_A_CPU1_SB_DQS_DN<3>")
	)
	(segment
		(start 66.637916 -200.572116)
		(end 66.3575 -200.2917)
		(width 0.20066)
		(layer "F.Cu")
		(net "M_A_CPU1_SB_DQS_DN<3>")
	)
	(segment
		(start 61.691012 -200.117456)
		(end 61.44006 -199.866504)
		(width 0.20066)
		(layer "F.Cu")
		(net "M_A_CPU1_SB_DQS_DN<3>")
	)
	(segment
		(start 84.280756 -220.576902)
		(end 84.280756 -220.449648)
		(width 0.088646)
		(layer "F.Cu")
		(net "M_A_CPU1_SB_DQS_DN<3>")
	)
	(segment
		(start 81.196434 -207.463898)
		(end 80.770476 -207.03794)
		(width 0.20066)
		(layer "F.Cu")
		(net "M_A_CPU1_SB_DQS_DN<3>")
	)
	(segment
		(start 83.251548 -209.695034)
		(end 83.251548 -209.519012)
		(width 0.20066)
		(layer "F.Cu")
		(net "M_A_CPU1_SB_DQS_DN<3>")
	)
	(segment
		(start 79.141574 -205.409038)
		(end 78.715616 -204.98308)
		(width 0.20066)
		(layer "F.Cu")
		(net "M_A_CPU1_SB_DQS_DN<3>")
	)
	(segment
		(start 83.760056 -214.052658)
		(end 83.760056 -214.033608)
		(width 0.1524)
		(layer "F.Cu")
		(net "M_A_CPU1_SB_DQS_DN<3>")
	)
	(segment
		(start 81.196434 -207.63992)
		(end 81.196434 -207.463898)
		(width 0.20066)
		(layer "F.Cu")
		(net "M_A_CPU1_SB_DQS_DN<3>")
	)
	(segment
		(start 59.002168 -200.285604)
		(end 59.27598 -200.559416)
		(width 0.20066)
		(layer "F.Cu")
		(net "M_A_CPU1_SB_DQS_DN<3>")
	)
	(segment
		(start 83.549998 -219.80144)
		(end 83.534504 -219.785946)
		(width 0.088646)
		(layer "F.Cu")
		(net "M_A_CPU1_SB_DQS_DN<3>")
	)
	(segment
		(start 54.22265 -200.137522)
		(end 54.481476 -200.137522)
		(width 0.20066)
		(layer "F.Cu")
		(net "M_A_CPU1_SB_DQS_DN<3>")
	)
	(segment
		(start 60.117228 -200.107296)
		(end 60.357766 -199.866758)
		(width 0.20066)
		(layer "F.Cu")
		(net "M_A_CPU1_SB_DQS_DN<3>")
	)
	(segment
		(start 66.3575 -200.2917)
		(end 66.237612 -200.2917)
		(width 0.20066)
		(layer "F.Cu")
		(net "M_A_CPU1_SB_DQS_DN<3>")
	)
	(segment
		(start 63.989458 -200.274682)
		(end 63.977012 -200.274682)
		(width 0.1016)
		(layer "F.Cu")
		(net "M_A_CPU1_SB_DQS_DN<3>")
	)
	(segment
		(start 84.141564 -220.310456)
		(end 84.013802 -220.310456)
		(width 0.088646)
		(layer "F.Cu")
		(net "M_A_CPU1_SB_DQS_DN<3>")
	)
	(segment
		(start 78.539594 -204.98308)
		(end 74.12863 -200.572116)
		(width 0.20066)
		(layer "F.Cu")
		(net "M_A_CPU1_SB_DQS_DN<3>")
	)
	(segment
		(start 78.715616 -204.98308)
		(end 78.539594 -204.98308)
		(width 0.20066)
		(layer "F.Cu")
		(net "M_A_CPU1_SB_DQS_DN<3>")
	)
	(segment
		(start 79.567024 -206.01051)
		(end 79.141574 -205.58506)
		(width 0.20066)
		(layer "F.Cu")
		(net "M_A_CPU1_SB_DQS_DN<3>")
	)
	(segment
		(start 74.12863 -200.572116)
		(end 66.637916 -200.572116)
		(width 0.20066)
		(layer "F.Cu")
		(net "M_A_CPU1_SB_DQS_DN<3>")
	)
	(segment
		(start 56.003698 -200.28662)
		(end 56.37911 -200.28662)
		(width 0.20066)
		(layer "F.Cu")
		(net "M_A_CPU1_SB_DQS_DN<3>")
	)
	(segment
		(start 83.676998 -210.120484)
		(end 83.251548 -209.695034)
		(width 0.20066)
		(layer "F.Cu")
		(net "M_A_CPU1_SB_DQS_DN<3>")
	)
	(segment
		(start 80.169004 -206.436468)
		(end 79.743046 -206.01051)
		(width 0.20066)
		(layer "F.Cu")
		(net "M_A_CPU1_SB_DQS_DN<3>")
	)
	(segment
		(start 83.251548 -209.519012)
		(end 82.82559 -209.093054)
		(width 0.20066)
		(layer "F.Cu")
		(net "M_A_CPU1_SB_DQS_DN<3>")
	)
	(segment
		(start 82.22361 -208.491074)
		(end 81.797906 -208.06537)
		(width 0.20066)
		(layer "F.Cu")
		(net "M_A_CPU1_SB_DQS_DN<3>")
	)
	(segment
		(start 66.237612 -200.2917)
		(end 64.006476 -200.2917)
		(width 0.1016)
		(layer "F.Cu")
		(net "M_A_CPU1_SB_DQS_DN<3>")
	)
	(segment
		(start 83.760056 -214.033608)
		(end 83.760056 -210.321144)
		(width 0.20066)
		(layer "F.Cu")
		(net "M_A_CPU1_SB_DQS_DN<3>")
	)
	(segment
		(start 84.432394 -220.728794)
		(end 84.280756 -220.576902)
		(width 0.088646)
		(layer "F.Cu")
		(net "M_A_CPU1_SB_DQS_DN<3>")
	)
	(segment
		(start 58.69813 -200.2917)
		(end 58.704226 -200.285604)
		(width 0.1016)
		(layer "F.Cu")
		(net "M_A_CPU1_SB_DQS_DN<3>")
	)
	(segment
		(start 54.481476 -200.137522)
		(end 55.50154 -200.560178)
		(width 0.20066)
		(layer "F.Cu")
		(net "M_A_CPU1_SB_DQS_DN<3>")
	)
	(segment
		(start 84.280756 -220.449648)
		(end 84.141564 -220.310456)
		(width 0.088646)
		(layer "F.Cu")
		(net "M_A_CPU1_SB_DQS_DN<3>")
	)
	(segment
		(start 63.503048 -200.359518)
		(end 63.503048 -200.54443)
		(width 0.20066)
		(layer "F.Cu")
		(net "M_A_CPU1_SB_DQS_DN<3>")
	)
	(segment
		(start 84.013802 -220.310456)
		(end 83.549998 -219.846652)
		(width 0.088646)
		(layer "F.Cu")
		(net "M_A_CPU1_SB_DQS_DN<3>")
	)
	(segment
		(start 56.38419 -200.2917)
		(end 58.69813 -200.2917)
		(width 0.1016)
		(layer "F.Cu")
		(net "M_A_CPU1_SB_DQS_DN<3>")
	)
	(segment
		(start 58.704226 -200.285604)
		(end 59.002168 -200.285604)
		(width 0.20066)
		(layer "F.Cu")
		(net "M_A_CPU1_SB_DQS_DN<3>")
	)
	(segment
		(start 82.899504 -219.150946)
		(end 82.899504 -215.52154)
		(width 0.1524)
		(layer "F.Cu")
		(net "M_A_CPU1_SB_DQS_DN<3>")
	)
	(segment
		(start 80.770476 -207.03794)
		(end 80.594454 -207.03794)
		(width 0.20066)
		(layer "F.Cu")
		(net "M_A_CPU1_SB_DQS_DN<3>")
	)
	(segment
		(start 82.899504 -215.52154)
		(end 83.714336 -214.706708)
		(width 0.1524)
		(layer "F.Cu")
		(net "M_A_CPU1_SB_DQS_DN<3>")
	)
	(segment
		(start 55.50154 -200.560178)
		(end 55.73014 -200.560178)
		(width 0.20066)
		(layer "F.Cu")
		(net "M_A_CPU1_SB_DQS_DN<3>")
	)
	(segment
		(start 83.760056 -210.321144)
		(end 83.676998 -210.120484)
		(width 0.20066)
		(layer "F.Cu")
		(net "M_A_CPU1_SB_DQS_DN<3>")
	)
	(segment
		(start 82.82559 -209.093054)
		(end 82.649568 -209.093054)
		(width 0.20066)
		(layer "F.Cu")
		(net "M_A_CPU1_SB_DQS_DN<3>")
	)
	(segment
		(start 79.141574 -205.58506)
		(end 79.141574 -205.409038)
		(width 0.20066)
		(layer "F.Cu")
		(net "M_A_CPU1_SB_DQS_DN<3>")
	)
	(segment
		(start 61.994288 -200.117456)
		(end 61.691012 -200.117456)
		(width 0.20066)
		(layer "F.Cu")
		(net "M_A_CPU1_SB_DQS_DN<3>")
	)
	(segment
		(start 63.503048 -200.54443)
		(end 63.439802 -200.607676)
		(width 0.20066)
		(layer "F.Cu")
		(net "M_A_CPU1_SB_DQS_DN<3>")
	)
	(segment
		(start 61.44006 -199.866504)
		(end 61.439806 -199.866758)
		(width 0.20066)
		(layer "F.Cu")
		(net "M_A_CPU1_SB_DQS_DN<3>")
	)
	(segment
		(start 77.975968 -216.566496)
		(end 77.69352 -216.284048)
		(width 0.1524)
		(layer "F.Cu")
		(net "M_A_CPU1_SB_DQS_DN<2>")
	)
	(segment
		(start 77.69352 -216.231724)
		(end 77.666596 -216.2048)
		(width 0.1524)
		(layer "F.Cu")
		(net "M_A_CPU1_SB_DQS_DN<2>")
	)
	(segment
		(start 79.836264 -224.865946)
		(end 78.230984 -223.260666)
		(width 0.1524)
		(layer "F.Cu")
		(net "M_A_CPU1_SB_DQS_DN<2>")
	)
	(segment
		(start 58.69813 -209.641694)
		(end 58.704226 -209.635598)
		(width 0.1016)
		(layer "F.Cu")
		(net "M_A_CPU1_SB_DQS_DN<2>")
	)
	(segment
		(start 72.10425 -210.642454)
		(end 72.10425 -210.466432)
		(width 0.20066)
		(layer "F.Cu")
		(net "M_A_CPU1_SB_DQS_DN<2>")
	)
	(segment
		(start 66.196464 -209.641694)
		(end 63.98641 -209.641694)
		(width 0.1016)
		(layer "F.Cu")
		(net "M_A_CPU1_SB_DQS_DN<2>")
	)
	(segment
		(start 63.98641 -209.641694)
		(end 63.977012 -209.632296)
		(width 0.1016)
		(layer "F.Cu")
		(net "M_A_CPU1_SB_DQS_DN<2>")
	)
	(segment
		(start 59.852306 -209.45729)
		(end 60.117228 -209.45729)
		(width 0.20066)
		(layer "F.Cu")
		(net "M_A_CPU1_SB_DQS_DN<2>")
	)
	(segment
		(start 78.230984 -223.260666)
		(end 78.230984 -217.182954)
		(width 0.1524)
		(layer "F.Cu")
		(net "M_A_CPU1_SB_DQS_DN<2>")
	)
	(segment
		(start 77.666596 -216.2048)
		(end 77.2414 -215.779604)
		(width 0.20066)
		(layer "F.Cu")
		(net "M_A_CPU1_SB_DQS_DN<2>")
	)
	(segment
		(start 73.13168 -211.493862)
		(end 72.705722 -211.067904)
		(width 0.20066)
		(layer "F.Cu")
		(net "M_A_CPU1_SB_DQS_DN<2>")
	)
	(segment
		(start 77.69352 -216.284048)
		(end 77.69352 -216.231724)
		(width 0.1524)
		(layer "F.Cu")
		(net "M_A_CPU1_SB_DQS_DN<2>")
	)
	(segment
		(start 75.18654 -213.724744)
		(end 75.18654 -213.548722)
		(width 0.20066)
		(layer "F.Cu")
		(net "M_A_CPU1_SB_DQS_DN<2>")
	)
	(segment
		(start 83.503008 -230.672132)
		(end 79.836264 -227.005388)
		(width 0.1524)
		(layer "F.Cu")
		(net "M_A_CPU1_SB_DQS_DN<2>")
	)
	(segment
		(start 69.294248 -209.887312)
		(end 69.169788 -209.762852)
		(width 0.20066)
		(layer "F.Cu")
		(net "M_A_CPU1_SB_DQS_DN<2>")
	)
	(segment
		(start 70.622668 -209.762852)
		(end 70.020688 -209.762852)
		(width 0.20066)
		(layer "F.Cu")
		(net "M_A_CPU1_SB_DQS_DN<2>")
	)
	(segment
		(start 66.212212 -209.63382)
		(end 66.204338 -209.63382)
		(width 0.1016)
		(layer "F.Cu")
		(net "M_A_CPU1_SB_DQS_DN<2>")
	)
	(segment
		(start 63.267844 -209.912204)
		(end 62.926976 -209.912204)
		(width 0.20066)
		(layer "F.Cu")
		(net "M_A_CPU1_SB_DQS_DN<2>")
	)
	(segment
		(start 74.58456 -213.122764)
		(end 74.15911 -212.697314)
		(width 0.20066)
		(layer "F.Cu")
		(net "M_A_CPU1_SB_DQS_DN<2>")
	)
	(segment
		(start 84.856066 -230.701088)
		(end 84.765896 -230.791258)
		(width 0.088646)
		(layer "F.Cu")
		(net "M_A_CPU1_SB_DQS_DN<2>")
	)
	(segment
		(start 56.011318 -209.628994)
		(end 56.37911 -209.628994)
		(width 0.20066)
		(layer "F.Cu")
		(net "M_A_CPU1_SB_DQS_DN<2>")
	)
	(segment
		(start 56.39181 -209.641694)
		(end 58.69813 -209.641694)
		(width 0.1016)
		(layer "F.Cu")
		(net "M_A_CPU1_SB_DQS_DN<2>")
	)
	(segment
		(start 56.37911 -209.628994)
		(end 56.39181 -209.641694)
		(width 0.1016)
		(layer "F.Cu")
		(net "M_A_CPU1_SB_DQS_DN<2>")
	)
	(segment
		(start 55.73014 -209.910172)
		(end 56.011318 -209.628994)
		(width 0.20066)
		(layer "F.Cu")
		(net "M_A_CPU1_SB_DQS_DN<2>")
	)
	(segment
		(start 76.21397 -214.576152)
		(end 75.788012 -214.150194)
		(width 0.20066)
		(layer "F.Cu")
		(net "M_A_CPU1_SB_DQS_DN<2>")
	)
	(segment
		(start 73.13168 -211.669884)
		(end 73.13168 -211.493862)
		(width 0.20066)
		(layer "F.Cu")
		(net "M_A_CPU1_SB_DQS_DN<2>")
	)
	(segment
		(start 59.002168 -209.635598)
		(end 59.27598 -209.90941)
		(width 0.20066)
		(layer "F.Cu")
		(net "M_A_CPU1_SB_DQS_DN<2>")
	)
	(segment
		(start 84.376768 -230.791258)
		(end 84.289646 -230.704136)
		(width 0.088646)
		(layer "F.Cu")
		(net "M_A_CPU1_SB_DQS_DN<2>")
	)
	(segment
		(start 69.169788 -209.762852)
		(end 68.567808 -209.762852)
		(width 0.20066)
		(layer "F.Cu")
		(net "M_A_CPU1_SB_DQS_DN<2>")
	)
	(segment
		(start 70.020688 -209.762852)
		(end 69.896228 -209.887312)
		(width 0.20066)
		(layer "F.Cu")
		(net "M_A_CPU1_SB_DQS_DN<2>")
	)
	(segment
		(start 72.705722 -211.067904)
		(end 72.5297 -211.067904)
		(width 0.20066)
		(layer "F.Cu")
		(net "M_A_CPU1_SB_DQS_DN<2>")
	)
	(segment
		(start 74.760582 -213.122764)
		(end 74.58456 -213.122764)
		(width 0.20066)
		(layer "F.Cu")
		(net "M_A_CPU1_SB_DQS_DN<2>")
	)
	(segment
		(start 63.547752 -209.632296)
		(end 63.267844 -209.912204)
		(width 0.20066)
		(layer "F.Cu")
		(net "M_A_CPU1_SB_DQS_DN<2>")
	)
	(segment
		(start 79.836264 -227.005388)
		(end 79.836264 -224.865946)
		(width 0.1524)
		(layer "F.Cu")
		(net "M_A_CPU1_SB_DQS_DN<2>")
	)
	(segment
		(start 83.932014 -230.672132)
		(end 83.503008 -230.672132)
		(width 0.1524)
		(layer "F.Cu")
		(net "M_A_CPU1_SB_DQS_DN<2>")
	)
	(segment
		(start 72.5297 -211.067904)
		(end 72.10425 -210.642454)
		(width 0.20066)
		(layer "F.Cu")
		(net "M_A_CPU1_SB_DQS_DN<2>")
	)
	(segment
		(start 59.27598 -209.90941)
		(end 59.400186 -209.90941)
		(width 0.20066)
		(layer "F.Cu")
		(net "M_A_CPU1_SB_DQS_DN<2>")
	)
	(segment
		(start 71.678292 -210.040474)
		(end 71.50227 -210.040474)
		(width 0.20066)
		(layer "F.Cu")
		(net "M_A_CPU1_SB_DQS_DN<2>")
	)
	(segment
		(start 68.567808 -209.762852)
		(end 68.443348 -209.887312)
		(width 0.20066)
		(layer "F.Cu")
		(net "M_A_CPU1_SB_DQS_DN<2>")
	)
	(segment
		(start 66.204338 -209.63382)
		(end 66.196464 -209.641694)
		(width 0.1016)
		(layer "F.Cu")
		(net "M_A_CPU1_SB_DQS_DN<2>")
	)
	(segment
		(start 84.856066 -230.622602)
		(end 84.856066 -230.701088)
		(width 0.088646)
		(layer "F.Cu")
		(net "M_A_CPU1_SB_DQS_DN<2>")
	)
	(segment
		(start 83.954112 -230.672132)
		(end 83.932014 -230.672132)
		(width 0.088646)
		(layer "F.Cu")
		(net "M_A_CPU1_SB_DQS_DN<2>")
	)
	(segment
		(start 69.896228 -209.887312)
		(end 69.294248 -209.887312)
		(width 0.20066)
		(layer "F.Cu")
		(net "M_A_CPU1_SB_DQS_DN<2>")
	)
	(segment
		(start 70.747128 -209.887312)
		(end 70.622668 -209.762852)
		(width 0.20066)
		(layer "F.Cu")
		(net "M_A_CPU1_SB_DQS_DN<2>")
	)
	(segment
		(start 60.357766 -209.216752)
		(end 60.947046 -209.216752)
		(width 0.20066)
		(layer "F.Cu")
		(net "M_A_CPU1_SB_DQS_DN<2>")
	)
	(segment
		(start 74.15911 -212.697314)
		(end 74.15911 -212.521292)
		(width 0.20066)
		(layer "F.Cu")
		(net "M_A_CPU1_SB_DQS_DN<2>")
	)
	(segment
		(start 76.21397 -214.752174)
		(end 76.21397 -214.576152)
		(width 0.20066)
		(layer "F.Cu")
		(net "M_A_CPU1_SB_DQS_DN<2>")
	)
	(segment
		(start 61.44006 -209.216498)
		(end 61.439806 -209.216752)
		(width 0.20066)
		(layer "F.Cu")
		(net "M_A_CPU1_SB_DQS_DN<2>")
	)
	(segment
		(start 59.400186 -209.90941)
		(end 59.852306 -209.45729)
		(width 0.20066)
		(layer "F.Cu")
		(net "M_A_CPU1_SB_DQS_DN<2>")
	)
	(segment
		(start 78.230984 -217.182954)
		(end 77.975968 -216.566496)
		(width 0.1524)
		(layer "F.Cu")
		(net "M_A_CPU1_SB_DQS_DN<2>")
	)
	(segment
		(start 71.50227 -210.040474)
		(end 71.349108 -209.887312)
		(width 0.20066)
		(layer "F.Cu")
		(net "M_A_CPU1_SB_DQS_DN<2>")
	)
	(segment
		(start 77.2414 -215.779604)
		(end 77.2414 -215.603582)
		(width 0.20066)
		(layer "F.Cu")
		(net "M_A_CPU1_SB_DQS_DN<2>")
	)
	(segment
		(start 84.765896 -230.791258)
		(end 84.376768 -230.791258)
		(width 0.088646)
		(layer "F.Cu")
		(net "M_A_CPU1_SB_DQS_DN<2>")
	)
	(segment
		(start 63.977012 -209.632296)
		(end 63.547752 -209.632296)
		(width 0.20066)
		(layer "F.Cu")
		(net "M_A_CPU1_SB_DQS_DN<2>")
	)
	(segment
		(start 73.55713 -212.095334)
		(end 73.13168 -211.669884)
		(width 0.20066)
		(layer "F.Cu")
		(net "M_A_CPU1_SB_DQS_DN<2>")
	)
	(segment
		(start 61.91631 -209.493612)
		(end 61.717174 -209.493612)
		(width 0.20066)
		(layer "F.Cu")
		(net "M_A_CPU1_SB_DQS_DN<2>")
	)
	(segment
		(start 61.439806 -209.216752)
		(end 60.947046 -209.216752)
		(width 0.20066)
		(layer "F.Cu")
		(net "M_A_CPU1_SB_DQS_DN<2>")
	)
	(segment
		(start 60.117228 -209.45729)
		(end 60.357766 -209.216752)
		(width 0.20066)
		(layer "F.Cu")
		(net "M_A_CPU1_SB_DQS_DN<2>")
	)
	(segment
		(start 71.349108 -209.887312)
		(end 70.747128 -209.887312)
		(width 0.20066)
		(layer "F.Cu")
		(net "M_A_CPU1_SB_DQS_DN<2>")
	)
	(segment
		(start 66.59499 -209.63382)
		(end 66.212212 -209.63382)
		(width 0.20066)
		(layer "F.Cu")
		(net "M_A_CPU1_SB_DQS_DN<2>")
	)
	(segment
		(start 62.926976 -209.912204)
		(end 61.91631 -209.493612)
		(width 0.20066)
		(layer "F.Cu")
		(net "M_A_CPU1_SB_DQS_DN<2>")
	)
	(segment
		(start 83.986116 -230.704136)
		(end 83.954112 -230.672132)
		(width 0.088646)
		(layer "F.Cu")
		(net "M_A_CPU1_SB_DQS_DN<2>")
	)
	(segment
		(start 77.2414 -215.603582)
		(end 76.815442 -215.177624)
		(width 0.20066)
		(layer "F.Cu")
		(net "M_A_CPU1_SB_DQS_DN<2>")
	)
	(segment
		(start 74.15911 -212.521292)
		(end 73.733152 -212.095334)
		(width 0.20066)
		(layer "F.Cu")
		(net "M_A_CPU1_SB_DQS_DN<2>")
	)
	(segment
		(start 84.289646 -230.704136)
		(end 83.986116 -230.704136)
		(width 0.088646)
		(layer "F.Cu")
		(net "M_A_CPU1_SB_DQS_DN<2>")
	)
	(segment
		(start 68.443348 -209.887312)
		(end 66.848482 -209.887312)
		(width 0.20066)
		(layer "F.Cu")
		(net "M_A_CPU1_SB_DQS_DN<2>")
	)
	(segment
		(start 76.63942 -215.177624)
		(end 76.21397 -214.752174)
		(width 0.20066)
		(layer "F.Cu")
		(net "M_A_CPU1_SB_DQS_DN<2>")
	)
	(segment
		(start 53.951886 -209.216752)
		(end 54.22265 -209.487516)
		(width 0.20066)
		(layer "F.Cu")
		(net "M_A_CPU1_SB_DQS_DN<2>")
	)
	(segment
		(start 66.848482 -209.887312)
		(end 66.59499 -209.63382)
		(width 0.20066)
		(layer "F.Cu")
		(net "M_A_CPU1_SB_DQS_DN<2>")
	)
	(segment
		(start 55.50154 -209.910172)
		(end 55.73014 -209.910172)
		(width 0.20066)
		(layer "F.Cu")
		(net "M_A_CPU1_SB_DQS_DN<2>")
	)
	(segment
		(start 73.733152 -212.095334)
		(end 73.55713 -212.095334)
		(width 0.20066)
		(layer "F.Cu")
		(net "M_A_CPU1_SB_DQS_DN<2>")
	)
	(segment
		(start 76.815442 -215.177624)
		(end 76.63942 -215.177624)
		(width 0.20066)
		(layer "F.Cu")
		(net "M_A_CPU1_SB_DQS_DN<2>")
	)
	(segment
		(start 75.61199 -214.150194)
		(end 75.18654 -213.724744)
		(width 0.20066)
		(layer "F.Cu")
		(net "M_A_CPU1_SB_DQS_DN<2>")
	)
	(segment
		(start 75.18654 -213.548722)
		(end 74.760582 -213.122764)
		(width 0.20066)
		(layer "F.Cu")
		(net "M_A_CPU1_SB_DQS_DN<2>")
	)
	(segment
		(start 58.704226 -209.635598)
		(end 59.002168 -209.635598)
		(width 0.20066)
		(layer "F.Cu")
		(net "M_A_CPU1_SB_DQS_DN<2>")
	)
	(segment
		(start 54.481476 -209.487516)
		(end 55.50154 -209.910172)
		(width 0.20066)
		(layer "F.Cu")
		(net "M_A_CPU1_SB_DQS_DN<2>")
	)
	(segment
		(start 54.22265 -209.487516)
		(end 54.481476 -209.487516)
		(width 0.20066)
		(layer "F.Cu")
		(net "M_A_CPU1_SB_DQS_DN<2>")
	)
	(segment
		(start 72.10425 -210.466432)
		(end 71.678292 -210.040474)
		(width 0.20066)
		(layer "F.Cu")
		(net "M_A_CPU1_SB_DQS_DN<2>")
	)
	(segment
		(start 53.403246 -209.216752)
		(end 53.951886 -209.216752)
		(width 0.20066)
		(layer "F.Cu")
		(net "M_A_CPU1_SB_DQS_DN<2>")
	)
	(segment
		(start 61.717174 -209.493612)
		(end 61.44006 -209.216498)
		(width 0.20066)
		(layer "F.Cu")
		(net "M_A_CPU1_SB_DQS_DN<2>")
	)
	(segment
		(start 75.788012 -214.150194)
		(end 75.61199 -214.150194)
		(width 0.20066)
		(layer "F.Cu")
		(net "M_A_CPU1_SB_DQS_DN<2>")
	)
	(segment
		(start 70.444614 -222.39986)
		(end 70.019164 -221.97441)
		(width 0.20066)
		(layer "F.Cu")
		(net "M_A_CPU1_SB_DQS_DN<1>")
	)
	(segment
		(start 74.902822 -229.59314)
		(end 74.778362 -229.7176)
		(width 0.20066)
		(layer "F.Cu")
		(net "M_A_CPU1_SB_DQS_DN<1>")
	)
	(segment
		(start 63.242444 -219.262706)
		(end 62.989714 -219.262706)
		(width 0.20066)
		(layer "F.Cu")
		(net "M_A_CPU1_SB_DQS_DN<1>")
	)
	(segment
		(start 61.711332 -218.837764)
		(end 61.44006 -218.566492)
		(width 0.20066)
		(layer "F.Cu")
		(net "M_A_CPU1_SB_DQS_DN<1>")
	)
	(segment
		(start 54.481476 -218.83751)
		(end 55.50154 -219.260166)
		(width 0.20066)
		(layer "F.Cu")
		(net "M_A_CPU1_SB_DQS_DN<1>")
	)
	(segment
		(start 70.019164 -221.97441)
		(end 70.019164 -221.798388)
		(width 0.20066)
		(layer "F.Cu")
		(net "M_A_CPU1_SB_DQS_DN<1>")
	)
	(segment
		(start 56.37911 -218.986608)
		(end 56.38419 -218.991688)
		(width 0.101854)
		(layer "F.Cu")
		(net "M_A_CPU1_SB_DQS_DN<1>")
	)
	(segment
		(start 76.40828 -229.752906)
		(end 76.306426 -229.754176)
		(width 0.1524)
		(layer "F.Cu")
		(net "M_A_CPU1_SB_DQS_DN<1>")
	)
	(segment
		(start 84.196428 -235.67771)
		(end 84.011516 -235.492798)
		(width 0.088646)
		(layer "F.Cu")
		(net "M_A_CPU1_SB_DQS_DN<1>")
	)
	(segment
		(start 74.778362 -229.7176)
		(end 74.176382 -229.7176)
		(width 0.20066)
		(layer "F.Cu")
		(net "M_A_CPU1_SB_DQS_DN<1>")
	)
	(segment
		(start 72.671686 -229.7176)
		(end 72.246236 -229.29215)
		(width 0.20066)
		(layer "F.Cu")
		(net "M_A_CPU1_SB_DQS_DN<1>")
	)
	(segment
		(start 75.504802 -229.59314)
		(end 74.902822 -229.59314)
		(width 0.20066)
		(layer "F.Cu")
		(net "M_A_CPU1_SB_DQS_DN<1>")
	)
	(segment
		(start 72.246236 -229.116128)
		(end 71.820278 -228.69017)
		(width 0.20066)
		(layer "F.Cu")
		(net "M_A_CPU1_SB_DQS_DN<1>")
	)
	(segment
		(start 69.417184 -221.37243)
		(end 68.991734 -220.94698)
		(width 0.20066)
		(layer "F.Cu")
		(net "M_A_CPU1_SB_DQS_DN<1>")
	)
	(segment
		(start 72.246236 -229.29215)
		(end 72.246236 -229.116128)
		(width 0.20066)
		(layer "F.Cu")
		(net "M_A_CPU1_SB_DQS_DN<1>")
	)
	(segment
		(start 71.218806 -228.26472)
		(end 71.218806 -228.088698)
		(width 0.20066)
		(layer "F.Cu")
		(net "M_A_CPU1_SB_DQS_DN<1>")
	)
	(segment
		(start 70.444614 -225.435668)
		(end 70.569074 -225.311208)
		(width 0.20066)
		(layer "F.Cu")
		(net "M_A_CPU1_SB_DQS_DN<1>")
	)
	(segment
		(start 74.176382 -229.7176)
		(end 74.051922 -229.59314)
		(width 0.20066)
		(layer "F.Cu")
		(net "M_A_CPU1_SB_DQS_DN<1>")
	)
	(segment
		(start 66.108072 -218.983052)
		(end 66.099436 -218.991688)
		(width 0.1016)
		(layer "F.Cu")
		(net "M_A_CPU1_SB_DQS_DN<1>")
	)
	(segment
		(start 76.269342 -229.7176)
		(end 76.231242 -229.7176)
		(width 0.1524)
		(layer "F.Cu")
		(net "M_A_CPU1_SB_DQS_DN<1>")
	)
	(segment
		(start 56.004206 -218.9861)
		(end 56.378602 -218.9861)
		(width 0.20066)
		(layer "F.Cu")
		(net "M_A_CPU1_SB_DQS_DN<1>")
	)
	(segment
		(start 66.55943 -218.983052)
		(end 66.237612 -218.983052)
		(width 0.20066)
		(layer "F.Cu")
		(net "M_A_CPU1_SB_DQS_DN<1>")
	)
	(segment
		(start 70.569074 -226.764088)
		(end 70.569074 -226.162108)
		(width 0.20066)
		(layer "F.Cu")
		(net "M_A_CPU1_SB_DQS_DN<1>")
	)
	(segment
		(start 66.829432 -219.253054)
		(end 66.55943 -218.983052)
		(width 0.20066)
		(layer "F.Cu")
		(net "M_A_CPU1_SB_DQS_DN<1>")
	)
	(segment
		(start 70.569074 -226.162108)
		(end 70.444614 -226.037648)
		(width 0.20066)
		(layer "F.Cu")
		(net "M_A_CPU1_SB_DQS_DN<1>")
	)
	(segment
		(start 68.565776 -220.345)
		(end 68.389754 -220.345)
		(width 0.20066)
		(layer "F.Cu")
		(net "M_A_CPU1_SB_DQS_DN<1>")
	)
	(segment
		(start 83.524344 -235.492798)
		(end 83.492594 -235.461048)
		(width 0.088646)
		(layer "F.Cu")
		(net "M_A_CPU1_SB_DQS_DN<1>")
	)
	(segment
		(start 70.444614 -223.131888)
		(end 70.444614 -222.39986)
		(width 0.20066)
		(layer "F.Cu")
		(net "M_A_CPU1_SB_DQS_DN<1>")
	)
	(segment
		(start 73.449942 -229.59314)
		(end 73.325482 -229.7176)
		(width 0.20066)
		(layer "F.Cu")
		(net "M_A_CPU1_SB_DQS_DN<1>")
	)
	(segment
		(start 76.231242 -229.7176)
		(end 75.629262 -229.7176)
		(width 0.20066)
		(layer "F.Cu")
		(net "M_A_CPU1_SB_DQS_DN<1>")
	)
	(segment
		(start 61.439806 -218.566746)
		(end 60.947046 -218.566746)
		(width 0.20066)
		(layer "F.Cu")
		(net "M_A_CPU1_SB_DQS_DN<1>")
	)
	(segment
		(start 68.991734 -220.94698)
		(end 68.991734 -220.770958)
		(width 0.20066)
		(layer "F.Cu")
		(net "M_A_CPU1_SB_DQS_DN<1>")
	)
	(segment
		(start 76.751942 -229.752906)
		(end 76.40828 -229.752906)
		(width 0.1524)
		(layer "F.Cu")
		(net "M_A_CPU1_SB_DQS_DN<1>")
	)
	(segment
		(start 63.907416 -218.991688)
		(end 63.900812 -218.985084)
		(width 0.1016)
		(layer "F.Cu")
		(net "M_A_CPU1_SB_DQS_DN<1>")
	)
	(segment
		(start 70.444614 -227.490528)
		(end 70.444614 -226.888548)
		(width 0.20066)
		(layer "F.Cu")
		(net "M_A_CPU1_SB_DQS_DN<1>")
	)
	(segment
		(start 70.019164 -221.798388)
		(end 69.593206 -221.37243)
		(width 0.20066)
		(layer "F.Cu")
		(net "M_A_CPU1_SB_DQS_DN<1>")
	)
	(segment
		(start 59.27598 -219.259404)
		(end 59.400186 -219.259404)
		(width 0.20066)
		(layer "F.Cu")
		(net "M_A_CPU1_SB_DQS_DN<1>")
	)
	(segment
		(start 84.749894 -235.67771)
		(end 84.196428 -235.67771)
		(width 0.088646)
		(layer "F.Cu")
		(net "M_A_CPU1_SB_DQS_DN<1>")
	)
	(segment
		(start 70.616826 -227.66274)
		(end 70.444614 -227.490528)
		(width 0.20066)
		(layer "F.Cu")
		(net "M_A_CPU1_SB_DQS_DN<1>")
	)
	(segment
		(start 66.099436 -218.991688)
		(end 63.907416 -218.991688)
		(width 0.1016)
		(layer "F.Cu")
		(net "M_A_CPU1_SB_DQS_DN<1>")
	)
	(segment
		(start 70.569074 -225.311208)
		(end 70.569074 -224.709228)
		(width 0.20066)
		(layer "F.Cu")
		(net "M_A_CPU1_SB_DQS_DN<1>")
	)
	(segment
		(start 77.160374 -229.92207)
		(end 76.751942 -229.752906)
		(width 0.1524)
		(layer "F.Cu")
		(net "M_A_CPU1_SB_DQS_DN<1>")
	)
	(segment
		(start 70.792848 -227.66274)
		(end 70.616826 -227.66274)
		(width 0.20066)
		(layer "F.Cu")
		(net "M_A_CPU1_SB_DQS_DN<1>")
	)
	(segment
		(start 71.820278 -228.69017)
		(end 71.644256 -228.69017)
		(width 0.20066)
		(layer "F.Cu")
		(net "M_A_CPU1_SB_DQS_DN<1>")
	)
	(segment
		(start 67.297808 -219.253054)
		(end 66.829432 -219.253054)
		(width 0.20066)
		(layer "F.Cu")
		(net "M_A_CPU1_SB_DQS_DN<1>")
	)
	(segment
		(start 66.237612 -218.983052)
		(end 66.108072 -218.983052)
		(width 0.1016)
		(layer "F.Cu")
		(net "M_A_CPU1_SB_DQS_DN<1>")
	)
	(segment
		(start 70.444614 -226.888548)
		(end 70.569074 -226.764088)
		(width 0.20066)
		(layer "F.Cu")
		(net "M_A_CPU1_SB_DQS_DN<1>")
	)
	(segment
		(start 70.569074 -223.256348)
		(end 70.444614 -223.131888)
		(width 0.20066)
		(layer "F.Cu")
		(net "M_A_CPU1_SB_DQS_DN<1>")
	)
	(segment
		(start 61.963808 -218.837764)
		(end 61.711332 -218.837764)
		(width 0.20066)
		(layer "F.Cu")
		(net "M_A_CPU1_SB_DQS_DN<1>")
	)
	(segment
		(start 60.357766 -218.566746)
		(end 60.947046 -218.566746)
		(width 0.20066)
		(layer "F.Cu")
		(net "M_A_CPU1_SB_DQS_DN<1>")
	)
	(segment
		(start 63.520066 -218.985084)
		(end 63.242444 -219.262706)
		(width 0.20066)
		(layer "F.Cu")
		(net "M_A_CPU1_SB_DQS_DN<1>")
	)
	(segment
		(start 84.856066 -235.571538)
		(end 84.749894 -235.67771)
		(width 0.088646)
		(layer "F.Cu")
		(net "M_A_CPU1_SB_DQS_DN<1>")
	)
	(segment
		(start 58.69813 -218.991688)
		(end 58.704226 -218.985592)
		(width 0.101854)
		(layer "F.Cu")
		(net "M_A_CPU1_SB_DQS_DN<1>")
	)
	(segment
		(start 76.306426 -229.754176)
		(end 76.269342 -229.7176)
		(width 0.1524)
		(layer "F.Cu")
		(net "M_A_CPU1_SB_DQS_DN<1>")
	)
	(segment
		(start 55.50154 -219.260166)
		(end 55.73014 -219.260166)
		(width 0.20066)
		(layer "F.Cu")
		(net "M_A_CPU1_SB_DQS_DN<1>")
	)
	(segment
		(start 54.22265 -218.83751)
		(end 54.481476 -218.83751)
		(width 0.20066)
		(layer "F.Cu")
		(net "M_A_CPU1_SB_DQS_DN<1>")
	)
	(segment
		(start 71.644256 -228.69017)
		(end 71.218806 -228.26472)
		(width 0.20066)
		(layer "F.Cu")
		(net "M_A_CPU1_SB_DQS_DN<1>")
	)
	(segment
		(start 68.991734 -220.770958)
		(end 68.565776 -220.345)
		(width 0.20066)
		(layer "F.Cu")
		(net "M_A_CPU1_SB_DQS_DN<1>")
	)
	(segment
		(start 71.218806 -228.088698)
		(end 70.792848 -227.66274)
		(width 0.20066)
		(layer "F.Cu")
		(net "M_A_CPU1_SB_DQS_DN<1>")
	)
	(segment
		(start 63.900812 -218.985084)
		(end 63.520066 -218.985084)
		(width 0.20066)
		(layer "F.Cu")
		(net "M_A_CPU1_SB_DQS_DN<1>")
	)
	(segment
		(start 60.117228 -218.807284)
		(end 60.357766 -218.566746)
		(width 0.20066)
		(layer "F.Cu")
		(net "M_A_CPU1_SB_DQS_DN<1>")
	)
	(segment
		(start 82.699352 -235.461048)
		(end 77.160374 -229.92207)
		(width 0.1524)
		(layer "F.Cu")
		(net "M_A_CPU1_SB_DQS_DN<1>")
	)
	(segment
		(start 83.492594 -235.461048)
		(end 83.470496 -235.461048)
		(width 0.088646)
		(layer "F.Cu")
		(net "M_A_CPU1_SB_DQS_DN<1>")
	)
	(segment
		(start 62.989714 -219.262706)
		(end 61.963808 -218.837764)
		(width 0.20066)
		(layer "F.Cu")
		(net "M_A_CPU1_SB_DQS_DN<1>")
	)
	(segment
		(start 74.051922 -229.59314)
		(end 73.449942 -229.59314)
		(width 0.20066)
		(layer "F.Cu")
		(net "M_A_CPU1_SB_DQS_DN<1>")
	)
	(segment
		(start 73.325482 -229.7176)
		(end 72.671686 -229.7176)
		(width 0.20066)
		(layer "F.Cu")
		(net "M_A_CPU1_SB_DQS_DN<1>")
	)
	(segment
		(start 84.856066 -235.506006)
		(end 84.856066 -235.571538)
		(width 0.088646)
		(layer "F.Cu")
		(net "M_A_CPU1_SB_DQS_DN<1>")
	)
	(segment
		(start 83.470496 -235.461048)
		(end 82.699352 -235.461048)
		(width 0.1524)
		(layer "F.Cu")
		(net "M_A_CPU1_SB_DQS_DN<1>")
	)
	(segment
		(start 70.569074 -224.709228)
		(end 70.444614 -224.584768)
		(width 0.20066)
		(layer "F.Cu")
		(net "M_A_CPU1_SB_DQS_DN<1>")
	)
	(segment
		(start 84.011516 -235.492798)
		(end 83.524344 -235.492798)
		(width 0.088646)
		(layer "F.Cu")
		(net "M_A_CPU1_SB_DQS_DN<1>")
	)
	(segment
		(start 70.444614 -223.982788)
		(end 70.569074 -223.858328)
		(width 0.20066)
		(layer "F.Cu")
		(net "M_A_CPU1_SB_DQS_DN<1>")
	)
	(segment
		(start 59.002168 -218.985592)
		(end 59.27598 -219.259404)
		(width 0.20066)
		(layer "F.Cu")
		(net "M_A_CPU1_SB_DQS_DN<1>")
	)
	(segment
		(start 56.378602 -218.9861)
		(end 56.37911 -218.986608)
		(width 0.20066)
		(layer "F.Cu")
		(net "M_A_CPU1_SB_DQS_DN<1>")
	)
	(segment
		(start 53.951886 -218.566746)
		(end 54.22265 -218.83751)
		(width 0.20066)
		(layer "F.Cu")
		(net "M_A_CPU1_SB_DQS_DN<1>")
	)
	(segment
		(start 53.403246 -218.566746)
		(end 53.951886 -218.566746)
		(width 0.20066)
		(layer "F.Cu")
		(net "M_A_CPU1_SB_DQS_DN<1>")
	)
	(segment
		(start 68.389754 -220.345)
		(end 67.297808 -219.253054)
		(width 0.20066)
		(layer "F.Cu")
		(net "M_A_CPU1_SB_DQS_DN<1>")
	)
	(segment
		(start 55.73014 -219.260166)
		(end 56.004206 -218.9861)
		(width 0.20066)
		(layer "F.Cu")
		(net "M_A_CPU1_SB_DQS_DN<1>")
	)
	(segment
		(start 70.444614 -224.584768)
		(end 70.444614 -223.982788)
		(width 0.20066)
		(layer "F.Cu")
		(net "M_A_CPU1_SB_DQS_DN<1>")
	)
	(segment
		(start 56.38419 -218.991688)
		(end 58.381138 -218.991688)
		(width 0.1016)
		(layer "F.Cu")
		(net "M_A_CPU1_SB_DQS_DN<1>")
	)
	(segment
		(start 59.852306 -218.807284)
		(end 60.117228 -218.807284)
		(width 0.20066)
		(layer "F.Cu")
		(net "M_A_CPU1_SB_DQS_DN<1>")
	)
	(segment
		(start 61.44006 -218.566492)
		(end 61.439806 -218.566746)
		(width 0.20066)
		(layer "F.Cu")
		(net "M_A_CPU1_SB_DQS_DN<1>")
	)
	(segment
		(start 59.400186 -219.259404)
		(end 59.852306 -218.807284)
		(width 0.20066)
		(layer "F.Cu")
		(net "M_A_CPU1_SB_DQS_DN<1>")
	)
	(segment
		(start 70.569074 -223.858328)
		(end 70.569074 -223.256348)
		(width 0.20066)
		(layer "F.Cu")
		(net "M_A_CPU1_SB_DQS_DN<1>")
	)
	(segment
		(start 58.381138 -218.991688)
		(end 58.69813 -218.991688)
		(width 0.101854)
		(layer "F.Cu")
		(net "M_A_CPU1_SB_DQS_DN<1>")
	)
	(segment
		(start 70.444614 -226.037648)
		(end 70.444614 -225.435668)
		(width 0.20066)
		(layer "F.Cu")
		(net "M_A_CPU1_SB_DQS_DN<1>")
	)
	(segment
		(start 69.593206 -221.37243)
		(end 69.417184 -221.37243)
		(width 0.20066)
		(layer "F.Cu")
		(net "M_A_CPU1_SB_DQS_DN<1>")
	)
	(segment
		(start 58.704226 -218.985592)
		(end 59.002168 -218.985592)
		(width 0.20066)
		(layer "F.Cu")
		(net "M_A_CPU1_SB_DQS_DN<1>")
	)
	(segment
		(start 75.629262 -229.7176)
		(end 75.504802 -229.59314)
		(width 0.20066)
		(layer "F.Cu")
		(net "M_A_CPU1_SB_DQS_DN<1>")
	)
	(segment
		(start 60.357766 -227.91674)
		(end 60.117228 -228.157278)
		(width 0.20066)
		(layer "F.Cu")
		(net "M_A_CPU1_SB_DQS_DN<0>")
	)
	(segment
		(start 60.117228 -228.157278)
		(end 59.753246 -228.157278)
		(width 0.20066)
		(layer "F.Cu")
		(net "M_A_CPU1_SB_DQS_DN<0>")
	)
	(segment
		(start 58.843418 -228.341682)
		(end 58.704226 -228.341682)
		(width 0.20066)
		(layer "F.Cu")
		(net "M_A_CPU1_SB_DQS_DN<0>")
	)
	(segment
		(start 56.39181 -228.336602)
		(end 56.37911 -228.336602)
		(width 0.101854)
		(layer "F.Cu")
		(net "M_A_CPU1_SB_DQS_DN<0>")
	)
	(segment
		(start 56.184546 -228.336602)
		(end 55.902098 -228.61905)
		(width 0.20066)
		(layer "F.Cu")
		(net "M_A_CPU1_SB_DQS_DN<0>")
	)
	(segment
		(start 62.051946 -227.91674)
		(end 60.947046 -227.91674)
		(width 0.20066)
		(layer "F.Cu")
		(net "M_A_CPU1_SB_DQS_DN<0>")
	)
	(segment
		(start 59.753246 -228.157278)
		(end 59.301126 -228.609398)
		(width 0.20066)
		(layer "F.Cu")
		(net "M_A_CPU1_SB_DQS_DN<0>")
	)
	(segment
		(start 88.145366 -237.947454)
		(end 88.145366 -237.411514)
		(width 0.20066)
		(layer "F.Cu")
		(net "M_A_CPU1_SB_DQS_DN<0>")
	)
	(segment
		(start 54.598824 -228.187504)
		(end 54.22265 -228.187504)
		(width 0.20066)
		(layer "F.Cu")
		(net "M_A_CPU1_SB_DQS_DN<0>")
	)
	(segment
		(start 58.704226 -228.341682)
		(end 58.381138 -228.341682)
		(width 0.101854)
		(layer "F.Cu")
		(net "M_A_CPU1_SB_DQS_DN<0>")
	)
	(segment
		(start 59.111134 -228.609398)
		(end 58.843418 -228.341682)
		(width 0.20066)
		(layer "F.Cu")
		(net "M_A_CPU1_SB_DQS_DN<0>")
	)
	(segment
		(start 55.902098 -228.61905)
		(end 55.640478 -228.61905)
		(width 0.20066)
		(layer "F.Cu")
		(net "M_A_CPU1_SB_DQS_DN<0>")
	)
	(segment
		(start 53.951886 -227.91674)
		(end 53.403246 -227.91674)
		(width 0.20066)
		(layer "F.Cu")
		(net "M_A_CPU1_SB_DQS_DN<0>")
	)
	(segment
		(start 56.39689 -228.341682)
		(end 56.39181 -228.336602)
		(width 0.101854)
		(layer "F.Cu")
		(net "M_A_CPU1_SB_DQS_DN<0>")
	)
	(segment
		(start 60.947046 -227.91674)
		(end 60.357766 -227.91674)
		(width 0.20066)
		(layer "F.Cu")
		(net "M_A_CPU1_SB_DQS_DN<0>")
	)
	(segment
		(start 54.22265 -228.187504)
		(end 53.951886 -227.91674)
		(width 0.20066)
		(layer "F.Cu")
		(net "M_A_CPU1_SB_DQS_DN<0>")
	)
	(segment
		(start 56.37911 -228.336602)
		(end 56.184546 -228.336602)
		(width 0.20066)
		(layer "F.Cu")
		(net "M_A_CPU1_SB_DQS_DN<0>")
	)
	(segment
		(start 55.640478 -228.61905)
		(end 54.598824 -228.187504)
		(width 0.20066)
		(layer "F.Cu")
		(net "M_A_CPU1_SB_DQS_DN<0>")
	)
	(segment
		(start 59.301126 -228.609398)
		(end 59.111134 -228.609398)
		(width 0.20066)
		(layer "F.Cu")
		(net "M_A_CPU1_SB_DQS_DN<0>")
	)
	(segment
		(start 58.381138 -228.341682)
		(end 56.39689 -228.341682)
		(width 0.1016)
		(layer "F.Cu")
		(net "M_A_CPU1_SB_DQS_DN<0>")
	)
	(segment
		(start 72.154542 -229.945946)
		(end 71.97852 -229.945946)
		(width 0.18288)
		(layer "In2.Cu")
		(net "M_A_CPU1_SB_DQS_DN<0>")
	)
	(segment
		(start 73.106534 -230.897938)
		(end 72.930512 -230.897938)
		(width 0.18288)
		(layer "In2.Cu")
		(net "M_A_CPU1_SB_DQS_DN<0>")
	)
	(segment
		(start 85.138514 -237.736126)
		(end 85.123782 -237.72749)
		(width 0.088646)
		(layer "In2.Cu")
		(net "M_A_CPU1_SB_DQS_DN<0>")
	)
	(segment
		(start 75.96251 -233.753914)
		(end 75.786488 -233.753914)
		(width 0.18288)
		(layer "In2.Cu")
		(net "M_A_CPU1_SB_DQS_DN<0>")
	)
	(segment
		(start 76.350622 -234.142026)
		(end 75.96251 -233.753914)
		(width 0.18288)
		(layer "In2.Cu")
		(net "M_A_CPU1_SB_DQS_DN<0>")
	)
	(segment
		(start 87.96147 -237.59541)
		(end 87.917274 -237.59541)
		(width 0.088646)
		(layer "In2.Cu")
		(net "M_A_CPU1_SB_DQS_DN<0>")
	)
	(segment
		(start 74.058526 -231.84993)
		(end 73.882504 -231.84993)
		(width 0.18288)
		(layer "In2.Cu")
		(net "M_A_CPU1_SB_DQS_DN<0>")
	)
	(segment
		(start 76.914502 -234.705906)
		(end 76.73848 -234.705906)
		(width 0.18288)
		(layer "In2.Cu")
		(net "M_A_CPU1_SB_DQS_DN<0>")
	)
	(segment
		(start 68.622926 -228.606096)
		(end 68.498466 -228.481636)
		(width 0.18288)
		(layer "In2.Cu")
		(net "M_A_CPU1_SB_DQS_DN<0>")
	)
	(segment
		(start 71.026528 -228.993954)
		(end 70.63867 -228.606096)
		(width 0.18288)
		(layer "In2.Cu")
		(net "M_A_CPU1_SB_DQS_DN<0>")
	)
	(segment
		(start 82.759296 -237.58398)
		(end 79.616554 -237.58398)
		(width 0.18288)
		(layer "In2.Cu")
		(net "M_A_CPU1_SB_DQS_DN<0>")
	)
	(segment
		(start 64.587628 -228.586538)
		(end 64.445896 -228.444806)
		(width 0.18288)
		(layer "In2.Cu")
		(net "M_A_CPU1_SB_DQS_DN<0>")
	)
	(segment
		(start 76.350622 -234.318048)
		(end 76.350622 -234.142026)
		(width 0.18288)
		(layer "In2.Cu")
		(net "M_A_CPU1_SB_DQS_DN<0>")
	)
	(segment
		(start 66.348864 -228.341682)
		(end 65.959228 -228.341682)
		(width 0.18288)
		(layer "In2.Cu")
		(net "M_A_CPU1_SB_DQS_DN<0>")
	)
	(segment
		(start 65.714372 -228.586538)
		(end 64.587628 -228.586538)
		(width 0.18288)
		(layer "In2.Cu")
		(net "M_A_CPU1_SB_DQS_DN<0>")
	)
	(segment
		(start 71.20255 -228.993954)
		(end 71.026528 -228.993954)
		(width 0.18288)
		(layer "In2.Cu")
		(net "M_A_CPU1_SB_DQS_DN<0>")
	)
	(segment
		(start 69.969126 -228.606096)
		(end 69.844666 -228.481636)
		(width 0.18288)
		(layer "In2.Cu")
		(net "M_A_CPU1_SB_DQS_DN<0>")
	)
	(segment
		(start 68.498466 -228.481636)
		(end 67.949826 -228.481636)
		(width 0.18288)
		(layer "In2.Cu")
		(net "M_A_CPU1_SB_DQS_DN<0>")
	)
	(segment
		(start 72.542654 -230.51008)
		(end 72.542654 -230.334058)
		(width 0.18288)
		(layer "In2.Cu")
		(net "M_A_CPU1_SB_DQS_DN<0>")
	)
	(segment
		(start 75.010518 -232.801922)
		(end 74.834496 -232.801922)
		(width 0.18288)
		(layer "In2.Cu")
		(net "M_A_CPU1_SB_DQS_DN<0>")
	)
	(segment
		(start 63.28791 -227.931218)
		(end 62.67069 -228.186742)
		(width 0.18288)
		(layer "In2.Cu")
		(net "M_A_CPU1_SB_DQS_DN<0>")
	)
	(segment
		(start 63.932308 -227.931218)
		(end 63.28791 -227.931218)
		(width 0.18288)
		(layer "In2.Cu")
		(net "M_A_CPU1_SB_DQS_DN<0>")
	)
	(segment
		(start 70.63867 -228.606096)
		(end 69.969126 -228.606096)
		(width 0.18288)
		(layer "In2.Cu")
		(net "M_A_CPU1_SB_DQS_DN<0>")
	)
	(segment
		(start 67.825366 -228.606096)
		(end 66.613278 -228.606096)
		(width 0.18288)
		(layer "In2.Cu")
		(net "M_A_CPU1_SB_DQS_DN<0>")
	)
	(segment
		(start 86.078568 -237.736126)
		(end 86.068154 -237.73003)
		(width 0.088646)
		(layer "In2.Cu")
		(net "M_A_CPU1_SB_DQS_DN<0>")
	)
	(segment
		(start 62.67069 -228.186742)
		(end 62.321948 -228.186742)
		(width 0.18288)
		(layer "In2.Cu")
		(net "M_A_CPU1_SB_DQS_DN<0>")
	)
	(segment
		(start 75.39863 -233.366056)
		(end 75.39863 -233.190034)
		(width 0.18288)
		(layer "In2.Cu")
		(net "M_A_CPU1_SB_DQS_DN<0>")
	)
	(segment
		(start 65.959228 -228.341682)
		(end 65.714372 -228.586538)
		(width 0.18288)
		(layer "In2.Cu")
		(net "M_A_CPU1_SB_DQS_DN<0>")
	)
	(segment
		(start 72.542654 -230.334058)
		(end 72.154542 -229.945946)
		(width 0.18288)
		(layer "In2.Cu")
		(net "M_A_CPU1_SB_DQS_DN<0>")
	)
	(segment
		(start 74.446638 -232.238042)
		(end 74.058526 -231.84993)
		(width 0.18288)
		(layer "In2.Cu")
		(net "M_A_CPU1_SB_DQS_DN<0>")
	)
	(segment
		(start 75.39863 -233.190034)
		(end 75.010518 -232.801922)
		(width 0.18288)
		(layer "In2.Cu")
		(net "M_A_CPU1_SB_DQS_DN<0>")
	)
	(segment
		(start 64.401446 -228.416612)
		(end 64.201802 -228.216968)
		(width 0.16002)
		(layer "In2.Cu")
		(net "M_A_CPU1_SB_DQS_DN<0>")
	)
	(segment
		(start 75.786488 -233.753914)
		(end 75.39863 -233.366056)
		(width 0.18288)
		(layer "In2.Cu")
		(net "M_A_CPU1_SB_DQS_DN<0>")
	)
	(segment
		(start 62.321948 -228.186742)
		(end 62.051946 -227.91674)
		(width 0.18288)
		(layer "In2.Cu")
		(net "M_A_CPU1_SB_DQS_DN<0>")
	)
	(segment
		(start 88.145366 -237.411514)
		(end 87.96147 -237.59541)
		(width 0.088646)
		(layer "In2.Cu")
		(net "M_A_CPU1_SB_DQS_DN<0>")
	)
	(segment
		(start 74.446638 -232.414064)
		(end 74.446638 -232.238042)
		(width 0.18288)
		(layer "In2.Cu")
		(net "M_A_CPU1_SB_DQS_DN<0>")
	)
	(segment
		(start 73.882504 -231.84993)
		(end 73.494646 -231.462072)
		(width 0.18288)
		(layer "In2.Cu")
		(net "M_A_CPU1_SB_DQS_DN<0>")
	)
	(segment
		(start 69.296026 -228.481636)
		(end 69.171566 -228.606096)
		(width 0.18288)
		(layer "In2.Cu")
		(net "M_A_CPU1_SB_DQS_DN<0>")
	)
	(segment
		(start 66.613278 -228.606096)
		(end 66.348864 -228.341682)
		(width 0.18288)
		(layer "In2.Cu")
		(net "M_A_CPU1_SB_DQS_DN<0>")
	)
	(segment
		(start 64.201802 -228.200712)
		(end 64.173608 -228.172518)
		(width 0.16002)
		(layer "In2.Cu")
		(net "M_A_CPU1_SB_DQS_DN<0>")
	)
	(segment
		(start 67.949826 -228.481636)
		(end 67.825366 -228.606096)
		(width 0.18288)
		(layer "In2.Cu")
		(net "M_A_CPU1_SB_DQS_DN<0>")
	)
	(segment
		(start 69.171566 -228.606096)
		(end 68.622926 -228.606096)
		(width 0.18288)
		(layer "In2.Cu")
		(net "M_A_CPU1_SB_DQS_DN<0>")
	)
	(segment
		(start 76.73848 -234.705906)
		(end 76.350622 -234.318048)
		(width 0.18288)
		(layer "In2.Cu")
		(net "M_A_CPU1_SB_DQS_DN<0>")
	)
	(segment
		(start 77.302614 -235.27004)
		(end 77.302614 -235.094018)
		(width 0.18288)
		(layer "In2.Cu")
		(net "M_A_CPU1_SB_DQS_DN<0>")
	)
	(segment
		(start 64.201802 -228.216968)
		(end 64.201802 -228.200712)
		(width 0.16002)
		(layer "In2.Cu")
		(net "M_A_CPU1_SB_DQS_DN<0>")
	)
	(segment
		(start 73.494646 -231.28605)
		(end 73.106534 -230.897938)
		(width 0.18288)
		(layer "In2.Cu")
		(net "M_A_CPU1_SB_DQS_DN<0>")
	)
	(segment
		(start 64.173608 -228.172518)
		(end 63.932308 -227.931218)
		(width 0.18288)
		(layer "In2.Cu")
		(net "M_A_CPU1_SB_DQS_DN<0>")
	)
	(segment
		(start 82.81924 -237.643924)
		(end 82.759296 -237.58398)
		(width 0.088646)
		(layer "In2.Cu")
		(net "M_A_CPU1_SB_DQS_DN<0>")
	)
	(segment
		(start 83.853782 -237.643924)
		(end 82.81924 -237.643924)
		(width 0.088646)
		(layer "In2.Cu")
		(net "M_A_CPU1_SB_DQS_DN<0>")
	)
	(segment
		(start 71.590662 -229.558088)
		(end 71.590662 -229.382066)
		(width 0.18288)
		(layer "In2.Cu")
		(net "M_A_CPU1_SB_DQS_DN<0>")
	)
	(segment
		(start 73.494646 -231.462072)
		(end 73.494646 -231.28605)
		(width 0.18288)
		(layer "In2.Cu")
		(net "M_A_CPU1_SB_DQS_DN<0>")
	)
	(segment
		(start 71.590662 -229.382066)
		(end 71.20255 -228.993954)
		(width 0.18288)
		(layer "In2.Cu")
		(net "M_A_CPU1_SB_DQS_DN<0>")
	)
	(segment
		(start 64.417702 -228.416612)
		(end 64.401446 -228.416612)
		(width 0.16002)
		(layer "In2.Cu")
		(net "M_A_CPU1_SB_DQS_DN<0>")
	)
	(segment
		(start 77.302614 -235.094018)
		(end 76.914502 -234.705906)
		(width 0.18288)
		(layer "In2.Cu")
		(net "M_A_CPU1_SB_DQS_DN<0>")
	)
	(segment
		(start 71.97852 -229.945946)
		(end 71.590662 -229.558088)
		(width 0.18288)
		(layer "In2.Cu")
		(net "M_A_CPU1_SB_DQS_DN<0>")
	)
	(segment
		(start 64.445896 -228.444806)
		(end 64.417702 -228.416612)
		(width 0.16002)
		(layer "In2.Cu")
		(net "M_A_CPU1_SB_DQS_DN<0>")
	)
	(segment
		(start 87.018114 -237.736126)
		(end 87.0077 -237.73003)
		(width 0.088646)
		(layer "In2.Cu")
		(net "M_A_CPU1_SB_DQS_DN<0>")
	)
	(segment
		(start 69.844666 -228.481636)
		(end 69.296026 -228.481636)
		(width 0.18288)
		(layer "In2.Cu")
		(net "M_A_CPU1_SB_DQS_DN<0>")
	)
	(segment
		(start 74.834496 -232.801922)
		(end 74.446638 -232.414064)
		(width 0.18288)
		(layer "In2.Cu")
		(net "M_A_CPU1_SB_DQS_DN<0>")
	)
	(segment
		(start 79.616554 -237.58398)
		(end 77.302614 -235.27004)
		(width 0.18288)
		(layer "In2.Cu")
		(net "M_A_CPU1_SB_DQS_DN<0>")
	)
	(segment
		(start 72.930512 -230.897938)
		(end 72.542654 -230.51008)
		(width 0.18288)
		(layer "In2.Cu")
		(net "M_A_CPU1_SB_DQS_DN<0>")
	)
	(arc
		(start 84.57311 -237.736126)
		(mid 84.385912 -237.786269)
		(end 84.198714 -237.736126)
		(width 0.088646)
		(layer "In2.Cu")
		(net "M_A_CPU1_SB_DQS_DN<0>")
	)
	(arc
		(start 85.123782 -237.72749)
		(mid 84.847307 -237.66017)
		(end 84.57311 -237.736126)
		(width 0.088646)
		(layer "In2.Cu")
		(net "M_A_CPU1_SB_DQS_DN<0>")
	)
	(arc
		(start 87.392256 -237.736126)
		(mid 87.205168 -237.786269)
		(end 87.018114 -237.736126)
		(width 0.088646)
		(layer "In2.Cu")
		(net "M_A_CPU1_SB_DQS_DN<0>")
	)
	(arc
		(start 87.0077 -237.73003)
		(mid 86.729522 -237.660307)
		(end 86.452964 -237.736126)
		(width 0.088646)
		(layer "In2.Cu")
		(net "M_A_CPU1_SB_DQS_DN<0>")
	)
	(arc
		(start 86.452964 -237.736126)
		(mid 86.265766 -237.786269)
		(end 86.078568 -237.736126)
		(width 0.088646)
		(layer "In2.Cu")
		(net "M_A_CPU1_SB_DQS_DN<0>")
	)
	(arc
		(start 86.068154 -237.73003)
		(mid 85.789722 -237.660184)
		(end 85.51291 -237.736126)
		(width 0.088646)
		(layer "In2.Cu")
		(net "M_A_CPU1_SB_DQS_DN<0>")
	)
	(arc
		(start 84.198714 -237.736126)
		(mid 84.032337 -237.66725)
		(end 83.853782 -237.643924)
		(width 0.088646)
		(layer "In2.Cu")
		(net "M_A_CPU1_SB_DQS_DN<0>")
	)
	(arc
		(start 85.51291 -237.736126)
		(mid 85.325712 -237.786269)
		(end 85.138514 -237.736126)
		(width 0.088646)
		(layer "In2.Cu")
		(net "M_A_CPU1_SB_DQS_DN<0>")
	)
	(arc
		(start 87.917274 -237.59541)
		(mid 87.645496 -237.631192)
		(end 87.392256 -237.736126)
		(width 0.088646)
		(layer "In2.Cu")
		(net "M_A_CPU1_SB_DQS_DN<0>")
	)
	(segment
		(start 55.583328 -220.846142)
		(end 55.747666 -220.681804)
		(width 0.20066)
		(layer "F.Cu")
		(net "M_A_CPU1_SB_DQ<9>")
	)
	(segment
		(start 54.865016 -221.26829)
		(end 55.390288 -221.26829)
		(width 0.20066)
		(layer "F.Cu")
		(net "M_A_CPU1_SB_DQ<9>")
	)
	(segment
		(start 73.580244 -231.798368)
		(end 73.987152 -231.798368)
		(width 0.20066)
		(layer "F.Cu")
		(net "M_A_CPU1_SB_DQ<9>")
	)
	(segment
		(start 58.774584 -220.69171)
		(end 59.334146 -221.251272)
		(width 0.20066)
		(layer "F.Cu")
		(net "M_A_CPU1_SB_DQ<9>")
	)
	(segment
		(start 66.34861 -221.54261)
		(end 66.57975 -221.31147)
		(width 0.20066)
		(layer "F.Cu")
		(net "M_A_CPU1_SB_DQ<9>")
	)
	(segment
		(start 59.334146 -221.251272)
		(end 59.989212 -221.251272)
		(width 0.20066)
		(layer "F.Cu")
		(net "M_A_CPU1_SB_DQ<9>")
	)
	(segment
		(start 66.240914 -221.541594)
		(end 66.24193 -221.54261)
		(width 0.101854)
		(layer "F.Cu")
		(net "M_A_CPU1_SB_DQ<9>")
	)
	(segment
		(start 68.106036 -228.492304)
		(end 68.106036 -228.776276)
		(width 0.20066)
		(layer "F.Cu")
		(net "M_A_CPU1_SB_DQ<9>")
	)
	(segment
		(start 68.106036 -228.776276)
		(end 68.324984 -228.995224)
		(width 0.20066)
		(layer "F.Cu")
		(net "M_A_CPU1_SB_DQ<9>")
	)
	(segment
		(start 69.188838 -228.699314)
		(end 71.9836 -231.494076)
		(width 0.20066)
		(layer "F.Cu")
		(net "M_A_CPU1_SB_DQ<9>")
	)
	(segment
		(start 62.034674 -221.116652)
		(end 63.02883 -221.333314)
		(width 0.20066)
		(layer "F.Cu")
		(net "M_A_CPU1_SB_DQ<9>")
	)
	(segment
		(start 55.583328 -221.07525)
		(end 55.583328 -220.846142)
		(width 0.20066)
		(layer "F.Cu")
		(net "M_A_CPU1_SB_DQ<9>")
	)
	(segment
		(start 71.9836 -231.494076)
		(end 73.275952 -231.494076)
		(width 0.20066)
		(layer "F.Cu")
		(net "M_A_CPU1_SB_DQ<9>")
	)
	(segment
		(start 59.989212 -221.251272)
		(end 60.123832 -221.116652)
		(width 0.20066)
		(layer "F.Cu")
		(net "M_A_CPU1_SB_DQ<9>")
	)
	(segment
		(start 66.24701 -221.54261)
		(end 66.34861 -221.54261)
		(width 0.20066)
		(layer "F.Cu")
		(net "M_A_CPU1_SB_DQ<9>")
	)
	(segment
		(start 55.390288 -221.26829)
		(end 55.583328 -221.07525)
		(width 0.20066)
		(layer "F.Cu")
		(net "M_A_CPU1_SB_DQ<9>")
	)
	(segment
		(start 75.002644 -231.798368)
		(end 75.409552 -231.798368)
		(width 0.20066)
		(layer "F.Cu")
		(net "M_A_CPU1_SB_DQ<9>")
	)
	(segment
		(start 73.275952 -231.494076)
		(end 73.580244 -231.798368)
		(width 0.20066)
		(layer "F.Cu")
		(net "M_A_CPU1_SB_DQ<9>")
	)
	(segment
		(start 53.403246 -221.116652)
		(end 54.713378 -221.116652)
		(width 0.20066)
		(layer "F.Cu")
		(net "M_A_CPU1_SB_DQ<9>")
	)
	(segment
		(start 68.017136 -227.527612)
		(end 68.401946 -227.912422)
		(width 0.20066)
		(layer "F.Cu")
		(net "M_A_CPU1_SB_DQ<9>")
	)
	(segment
		(start 60.947046 -221.116652)
		(end 62.034674 -221.116652)
		(width 0.20066)
		(layer "F.Cu")
		(net "M_A_CPU1_SB_DQ<9>")
	)
	(segment
		(start 63.977012 -221.553024)
		(end 63.988442 -221.541594)
		(width 0.1016)
		(layer "F.Cu")
		(net "M_A_CPU1_SB_DQ<9>")
	)
	(segment
		(start 83.751166 -236.374686)
		(end 83.80603 -236.319822)
		(width 0.088646)
		(layer "F.Cu")
		(net "M_A_CPU1_SB_DQ<9>")
	)
	(segment
		(start 74.291444 -231.494076)
		(end 74.698352 -231.494076)
		(width 0.20066)
		(layer "F.Cu")
		(net "M_A_CPU1_SB_DQ<9>")
	)
	(segment
		(start 68.904866 -228.699314)
		(end 69.188838 -228.699314)
		(width 0.20066)
		(layer "F.Cu")
		(net "M_A_CPU1_SB_DQ<9>")
	)
	(segment
		(start 58.704226 -220.69171)
		(end 58.774584 -220.69171)
		(width 0.20066)
		(layer "F.Cu")
		(net "M_A_CPU1_SB_DQ<9>")
	)
	(segment
		(start 63.02883 -221.333314)
		(end 63.676784 -221.553024)
		(width 0.20066)
		(layer "F.Cu")
		(net "M_A_CPU1_SB_DQ<9>")
	)
	(segment
		(start 68.017136 -222.250508)
		(end 68.017136 -227.527612)
		(width 0.20066)
		(layer "F.Cu")
		(net "M_A_CPU1_SB_DQ<9>")
	)
	(segment
		(start 55.747666 -220.681804)
		(end 56.37911 -220.681804)
		(width 0.20066)
		(layer "F.Cu")
		(net "M_A_CPU1_SB_DQ<9>")
	)
	(segment
		(start 63.988442 -221.541594)
		(end 65.855342 -221.541594)
		(width 0.1016)
		(layer "F.Cu")
		(net "M_A_CPU1_SB_DQ<9>")
	)
	(segment
		(start 83.521296 -236.374686)
		(end 83.751166 -236.374686)
		(width 0.088646)
		(layer "F.Cu")
		(net "M_A_CPU1_SB_DQ<9>")
	)
	(segment
		(start 66.24193 -221.54261)
		(end 66.24701 -221.54261)
		(width 0.101854)
		(layer "F.Cu")
		(net "M_A_CPU1_SB_DQ<9>")
	)
	(segment
		(start 68.608956 -228.995224)
		(end 68.904866 -228.699314)
		(width 0.20066)
		(layer "F.Cu")
		(net "M_A_CPU1_SB_DQ<9>")
	)
	(segment
		(start 75.713844 -231.494076)
		(end 76.332842 -231.494076)
		(width 0.20066)
		(layer "F.Cu")
		(net "M_A_CPU1_SB_DQ<9>")
	)
	(segment
		(start 67.078098 -221.31147)
		(end 68.017136 -222.250508)
		(width 0.20066)
		(layer "F.Cu")
		(net "M_A_CPU1_SB_DQ<9>")
	)
	(segment
		(start 60.123832 -221.116652)
		(end 60.947046 -221.116652)
		(width 0.20066)
		(layer "F.Cu")
		(net "M_A_CPU1_SB_DQ<9>")
	)
	(segment
		(start 68.401946 -228.196394)
		(end 68.106036 -228.492304)
		(width 0.20066)
		(layer "F.Cu")
		(net "M_A_CPU1_SB_DQ<9>")
	)
	(segment
		(start 68.401946 -227.912422)
		(end 68.401946 -228.196394)
		(width 0.20066)
		(layer "F.Cu")
		(net "M_A_CPU1_SB_DQ<9>")
	)
	(segment
		(start 54.713378 -221.116652)
		(end 54.865016 -221.26829)
		(width 0.20066)
		(layer "F.Cu")
		(net "M_A_CPU1_SB_DQ<9>")
	)
	(segment
		(start 76.332842 -231.494076)
		(end 77.474318 -231.494076)
		(width 0.1016)
		(layer "F.Cu")
		(net "M_A_CPU1_SB_DQ<9>")
	)
	(segment
		(start 82.354928 -236.374686)
		(end 83.521296 -236.374686)
		(width 0.1016)
		(layer "F.Cu")
		(net "M_A_CPU1_SB_DQ<9>")
	)
	(segment
		(start 83.80603 -236.319822)
		(end 85.325712 -236.319822)
		(width 0.088646)
		(layer "F.Cu")
		(net "M_A_CPU1_SB_DQ<9>")
	)
	(segment
		(start 66.57975 -221.31147)
		(end 67.078098 -221.31147)
		(width 0.20066)
		(layer "F.Cu")
		(net "M_A_CPU1_SB_DQ<9>")
	)
	(segment
		(start 74.698352 -231.494076)
		(end 75.002644 -231.798368)
		(width 0.20066)
		(layer "F.Cu")
		(net "M_A_CPU1_SB_DQ<9>")
	)
	(segment
		(start 58.304684 -220.69171)
		(end 58.704226 -220.69171)
		(width 0.101854)
		(layer "F.Cu")
		(net "M_A_CPU1_SB_DQ<9>")
	)
	(segment
		(start 73.987152 -231.798368)
		(end 74.291444 -231.494076)
		(width 0.20066)
		(layer "F.Cu")
		(net "M_A_CPU1_SB_DQ<9>")
	)
	(segment
		(start 75.409552 -231.798368)
		(end 75.713844 -231.494076)
		(width 0.20066)
		(layer "F.Cu")
		(net "M_A_CPU1_SB_DQ<9>")
	)
	(segment
		(start 56.389016 -220.69171)
		(end 56.610758 -220.69171)
		(width 0.101854)
		(layer "F.Cu")
		(net "M_A_CPU1_SB_DQ<9>")
	)
	(segment
		(start 77.474318 -231.494076)
		(end 82.354928 -236.374686)
		(width 0.1016)
		(layer "F.Cu")
		(net "M_A_CPU1_SB_DQ<9>")
	)
	(segment
		(start 63.676784 -221.553024)
		(end 63.977012 -221.553024)
		(width 0.20066)
		(layer "F.Cu")
		(net "M_A_CPU1_SB_DQ<9>")
	)
	(segment
		(start 56.610758 -220.69171)
		(end 58.304684 -220.69171)
		(width 0.1016)
		(layer "F.Cu")
		(net "M_A_CPU1_SB_DQ<9>")
	)
	(segment
		(start 65.855342 -221.541594)
		(end 66.240914 -221.541594)
		(width 0.101854)
		(layer "F.Cu")
		(net "M_A_CPU1_SB_DQ<9>")
	)
	(segment
		(start 68.324984 -228.995224)
		(end 68.608956 -228.995224)
		(width 0.20066)
		(layer "F.Cu")
		(net "M_A_CPU1_SB_DQ<9>")
	)
	(segment
		(start 56.37911 -220.681804)
		(end 56.389016 -220.69171)
		(width 0.101854)
		(layer "F.Cu")
		(net "M_A_CPU1_SB_DQ<9>")
	)
	(segment
		(start 58.704226 -222.378778)
		(end 58.801762 -222.378778)
		(width 0.20066)
		(layer "F.Cu")
		(net "M_A_CPU1_SB_DQ<8>")
	)
	(segment
		(start 66.321178 -222.372682)
		(end 66.186812 -222.372682)
		(width 0.20066)
		(layer "F.Cu")
		(net "M_A_CPU1_SB_DQ<8>")
	)
	(segment
		(start 62.73419 -222.816674)
		(end 60.947046 -222.816674)
		(width 0.20066)
		(layer "F.Cu")
		(net "M_A_CPU1_SB_DQ<8>")
	)
	(segment
		(start 83.521296 -236.984286)
		(end 82.101944 -236.984286)
		(width 0.1016)
		(layer "F.Cu")
		(net "M_A_CPU1_SB_DQ<8>")
	)
	(segment
		(start 70.120256 -233.110024)
		(end 66.70802 -229.697788)
		(width 0.20066)
		(layer "F.Cu")
		(net "M_A_CPU1_SB_DQ<8>")
	)
	(segment
		(start 54.684676 -222.993204)
		(end 55.329328 -222.993204)
		(width 0.20066)
		(layer "F.Cu")
		(net "M_A_CPU1_SB_DQ<8>")
	)
	(segment
		(start 63.067692 -222.483172)
		(end 62.73419 -222.816674)
		(width 0.20066)
		(layer "F.Cu")
		(net "M_A_CPU1_SB_DQ<8>")
	)
	(segment
		(start 56.392572 -222.391732)
		(end 56.610758 -222.391732)
		(width 0.101854)
		(layer "F.Cu")
		(net "M_A_CPU1_SB_DQ<8>")
	)
	(segment
		(start 63.633858 -222.483172)
		(end 63.067692 -222.483172)
		(width 0.20066)
		(layer "F.Cu")
		(net "M_A_CPU1_SB_DQ<8>")
	)
	(segment
		(start 54.508146 -222.816674)
		(end 54.684676 -222.993204)
		(width 0.20066)
		(layer "F.Cu")
		(net "M_A_CPU1_SB_DQ<8>")
	)
	(segment
		(start 66.70802 -222.759524)
		(end 66.321178 -222.372682)
		(width 0.20066)
		(layer "F.Cu")
		(net "M_A_CPU1_SB_DQ<8>")
	)
	(segment
		(start 84.053426 -236.732826)
		(end 83.801966 -236.984286)
		(width 0.088646)
		(layer "F.Cu")
		(net "M_A_CPU1_SB_DQ<8>")
	)
	(segment
		(start 63.977012 -222.383604)
		(end 63.733426 -222.383604)
		(width 0.20066)
		(layer "F.Cu")
		(net "M_A_CPU1_SB_DQ<8>")
	)
	(segment
		(start 58.801762 -222.378778)
		(end 59.339226 -222.916242)
		(width 0.20066)
		(layer "F.Cu")
		(net "M_A_CPU1_SB_DQ<8>")
	)
	(segment
		(start 66.186812 -222.372682)
		(end 66.148966 -222.372682)
		(width 0.101854)
		(layer "F.Cu")
		(net "M_A_CPU1_SB_DQ<8>")
	)
	(segment
		(start 55.751222 -222.37827)
		(end 56.37911 -222.37827)
		(width 0.20066)
		(layer "F.Cu")
		(net "M_A_CPU1_SB_DQ<8>")
	)
	(segment
		(start 63.733426 -222.383604)
		(end 63.633858 -222.483172)
		(width 0.20066)
		(layer "F.Cu")
		(net "M_A_CPU1_SB_DQ<8>")
	)
	(segment
		(start 58.349134 -222.391732)
		(end 58.691272 -222.391732)
		(width 0.101854)
		(layer "F.Cu")
		(net "M_A_CPU1_SB_DQ<8>")
	)
	(segment
		(start 59.339226 -222.916242)
		(end 60.054998 -222.916242)
		(width 0.20066)
		(layer "F.Cu")
		(net "M_A_CPU1_SB_DQ<8>")
	)
	(segment
		(start 66.70802 -229.697788)
		(end 66.70802 -222.759524)
		(width 0.20066)
		(layer "F.Cu")
		(net "M_A_CPU1_SB_DQ<8>")
	)
	(segment
		(start 82.101944 -236.984286)
		(end 78.227682 -233.110024)
		(width 0.1016)
		(layer "F.Cu")
		(net "M_A_CPU1_SB_DQ<8>")
	)
	(segment
		(start 58.691272 -222.391732)
		(end 58.704226 -222.378778)
		(width 0.101854)
		(layer "F.Cu")
		(net "M_A_CPU1_SB_DQ<8>")
	)
	(segment
		(start 56.37911 -222.37827)
		(end 56.392572 -222.391732)
		(width 0.101854)
		(layer "F.Cu")
		(net "M_A_CPU1_SB_DQ<8>")
	)
	(segment
		(start 55.329328 -222.993204)
		(end 55.583328 -222.739204)
		(width 0.20066)
		(layer "F.Cu")
		(net "M_A_CPU1_SB_DQ<8>")
	)
	(segment
		(start 66.148966 -222.372682)
		(end 66.129916 -222.391732)
		(width 0.101854)
		(layer "F.Cu")
		(net "M_A_CPU1_SB_DQ<8>")
	)
	(segment
		(start 66.129916 -222.391732)
		(end 64.185292 -222.391732)
		(width 0.1016)
		(layer "F.Cu")
		(net "M_A_CPU1_SB_DQ<8>")
	)
	(segment
		(start 56.610758 -222.391732)
		(end 58.349134 -222.391732)
		(width 0.1016)
		(layer "F.Cu")
		(net "M_A_CPU1_SB_DQ<8>")
	)
	(segment
		(start 63.98514 -222.391732)
		(end 63.977012 -222.383604)
		(width 0.101854)
		(layer "F.Cu")
		(net "M_A_CPU1_SB_DQ<8>")
	)
	(segment
		(start 64.185292 -222.391732)
		(end 63.98514 -222.391732)
		(width 0.101854)
		(layer "F.Cu")
		(net "M_A_CPU1_SB_DQ<8>")
	)
	(segment
		(start 78.227682 -233.110024)
		(end 77.806296 -233.110024)
		(width 0.1016)
		(layer "F.Cu")
		(net "M_A_CPU1_SB_DQ<8>")
	)
	(segment
		(start 85.409024 -237.03026)
		(end 85.027516 -236.809788)
		(width 0.088646)
		(layer "F.Cu")
		(net "M_A_CPU1_SB_DQ<8>")
	)
	(segment
		(start 55.583328 -222.546164)
		(end 55.751222 -222.37827)
		(width 0.20066)
		(layer "F.Cu")
		(net "M_A_CPU1_SB_DQ<8>")
	)
	(segment
		(start 83.801966 -236.984286)
		(end 83.521296 -236.984286)
		(width 0.088646)
		(layer "F.Cu")
		(net "M_A_CPU1_SB_DQ<8>")
	)
	(segment
		(start 60.154566 -222.816674)
		(end 60.947046 -222.816674)
		(width 0.20066)
		(layer "F.Cu")
		(net "M_A_CPU1_SB_DQ<8>")
	)
	(segment
		(start 55.583328 -222.739204)
		(end 55.583328 -222.546164)
		(width 0.20066)
		(layer "F.Cu")
		(net "M_A_CPU1_SB_DQ<8>")
	)
	(segment
		(start 53.403246 -222.816674)
		(end 54.508146 -222.816674)
		(width 0.20066)
		(layer "F.Cu")
		(net "M_A_CPU1_SB_DQ<8>")
	)
	(segment
		(start 60.054998 -222.916242)
		(end 60.154566 -222.816674)
		(width 0.20066)
		(layer "F.Cu")
		(net "M_A_CPU1_SB_DQ<8>")
	)
	(segment
		(start 77.806296 -233.110024)
		(end 70.120256 -233.110024)
		(width 0.20066)
		(layer "F.Cu")
		(net "M_A_CPU1_SB_DQ<8>")
	)
	(segment
		(start 84.73186 -236.732826)
		(end 84.053426 -236.732826)
		(width 0.088646)
		(layer "F.Cu")
		(net "M_A_CPU1_SB_DQ<8>")
	)
	(arc
		(start 85.027516 -236.809788)
		(mid 84.88462 -236.752351)
		(end 84.73186 -236.732826)
		(width 0.088646)
		(layer "F.Cu")
		(net "M_A_CPU1_SB_DQ<8>")
	)
	(arc
		(start 85.795866 -237.133892)
		(mid 85.595599 -237.107615)
		(end 85.409024 -237.03026)
		(width 0.088646)
		(layer "F.Cu")
		(net "M_A_CPU1_SB_DQ<8>")
	)
	(segment
		(start 65.047114 -223.666558)
		(end 63.705486 -223.666558)
		(width 0.20066)
		(layer "F.Cu")
		(net "M_A_CPU1_SB_DQ<7>")
	)
	(segment
		(start 59.837828 -224.109026)
		(end 59.822842 -224.109026)
		(width 0.101854)
		(layer "F.Cu")
		(net "M_A_CPU1_SB_DQ<7>")
	)
	(segment
		(start 59.855354 -224.0915)
		(end 59.837828 -224.109026)
		(width 0.101854)
		(layer "F.Cu")
		(net "M_A_CPU1_SB_DQ<7>")
	)
	(segment
		(start 61.839602 -224.092262)
		(end 61.83884 -224.0915)
		(width 0.1016)
		(layer "F.Cu")
		(net "M_A_CPU1_SB_DQ<7>")
	)
	(segment
		(start 59.913012 -224.0915)
		(end 59.855354 -224.0915)
		(width 0.101854)
		(layer "F.Cu")
		(net "M_A_CPU1_SB_DQ<7>")
	)
	(segment
		(start 90.024712 -236.319822)
		(end 90.024966 -236.319568)
		(width 0.20066)
		(layer "F.Cu")
		(net "M_A_CPU1_SB_DQ<7>")
	)
	(segment
		(start 62.669928 -223.964246)
		(end 62.541912 -224.092262)
		(width 0.20066)
		(layer "F.Cu")
		(net "M_A_CPU1_SB_DQ<7>")
	)
	(segment
		(start 61.83884 -224.0915)
		(end 59.913012 -224.0915)
		(width 0.1016)
		(layer "F.Cu")
		(net "M_A_CPU1_SB_DQ<7>")
	)
	(segment
		(start 59.066938 -223.666558)
		(end 57.503314 -223.666558)
		(width 0.20066)
		(layer "F.Cu")
		(net "M_A_CPU1_SB_DQ<7>")
	)
	(segment
		(start 63.705486 -223.666558)
		(end 63.46571 -223.426782)
		(width 0.20066)
		(layer "F.Cu")
		(net "M_A_CPU1_SB_DQ<7>")
	)
	(segment
		(start 62.669928 -223.690942)
		(end 62.669928 -223.964246)
		(width 0.20066)
		(layer "F.Cu")
		(net "M_A_CPU1_SB_DQ<7>")
	)
	(segment
		(start 62.934088 -223.426782)
		(end 62.669928 -223.690942)
		(width 0.20066)
		(layer "F.Cu")
		(net "M_A_CPU1_SB_DQ<7>")
	)
	(segment
		(start 62.147958 -224.092262)
		(end 62.072012 -224.092262)
		(width 0.101854)
		(layer "F.Cu")
		(net "M_A_CPU1_SB_DQ<7>")
	)
	(segment
		(start 66.152014 -223.666558)
		(end 65.047114 -223.666558)
		(width 0.20066)
		(layer "F.Cu")
		(net "M_A_CPU1_SB_DQ<7>")
	)
	(segment
		(start 62.541912 -224.092262)
		(end 62.147958 -224.092262)
		(width 0.20066)
		(layer "F.Cu")
		(net "M_A_CPU1_SB_DQ<7>")
	)
	(segment
		(start 90.024966 -236.319568)
		(end 90.024966 -235.783882)
		(width 0.20066)
		(layer "F.Cu")
		(net "M_A_CPU1_SB_DQ<7>")
	)
	(segment
		(start 62.072012 -224.092262)
		(end 61.839602 -224.092262)
		(width 0.1016)
		(layer "F.Cu")
		(net "M_A_CPU1_SB_DQ<7>")
	)
	(segment
		(start 59.822842 -224.109026)
		(end 59.509406 -224.109026)
		(width 0.20066)
		(layer "F.Cu")
		(net "M_A_CPU1_SB_DQ<7>")
	)
	(segment
		(start 59.509406 -224.109026)
		(end 59.066938 -223.666558)
		(width 0.20066)
		(layer "F.Cu")
		(net "M_A_CPU1_SB_DQ<7>")
	)
	(segment
		(start 63.46571 -223.426782)
		(end 62.934088 -223.426782)
		(width 0.20066)
		(layer "F.Cu")
		(net "M_A_CPU1_SB_DQ<7>")
	)
	(segment
		(start 66.69278 -223.529652)
		(end 66.482722 -223.529652)
		(width 0.18288)
		(layer "In2.Cu")
		(net "M_A_CPU1_SB_DQ<7>")
	)
	(segment
		(start 69.785992 -223.722692)
		(end 69.592952 -223.529652)
		(width 0.18288)
		(layer "In2.Cu")
		(net "M_A_CPU1_SB_DQ<7>")
	)
	(segment
		(start 89.367614 -235.294424)
		(end 89.352882 -235.285788)
		(width 0.088646)
		(layer "In2.Cu")
		(net "M_A_CPU1_SB_DQ<7>")
	)
	(segment
		(start 88.427814 -235.294424)
		(end 88.413082 -235.285788)
		(width 0.088646)
		(layer "In2.Cu")
		(net "M_A_CPU1_SB_DQ<7>")
	)
	(segment
		(start 67.667632 -224.113852)
		(end 67.474592 -224.306892)
		(width 0.18288)
		(layer "In2.Cu")
		(net "M_A_CPU1_SB_DQ<7>")
	)
	(segment
		(start 85.608414 -235.294424)
		(end 85.593682 -235.285788)
		(width 0.088646)
		(layer "In2.Cu")
		(net "M_A_CPU1_SB_DQ<7>")
	)
	(segment
		(start 66.897758 -223.73463)
		(end 66.69278 -223.529652)
		(width 0.18288)
		(layer "In2.Cu")
		(net "M_A_CPU1_SB_DQ<7>")
	)
	(segment
		(start 67.044316 -224.306892)
		(end 66.897758 -224.160334)
		(width 0.18288)
		(layer "In2.Cu")
		(net "M_A_CPU1_SB_DQ<7>")
	)
	(segment
		(start 89.367614 -235.29417)
		(end 89.367614 -235.294424)
		(width 0.088646)
		(layer "In2.Cu")
		(net "M_A_CPU1_SB_DQ<7>")
	)
	(segment
		(start 70.601586 -224.306892)
		(end 69.979032 -224.306892)
		(width 0.18288)
		(layer "In2.Cu")
		(net "M_A_CPU1_SB_DQ<7>")
	)
	(segment
		(start 69.785992 -224.113852)
		(end 69.785992 -223.722692)
		(width 0.18288)
		(layer "In2.Cu")
		(net "M_A_CPU1_SB_DQ<7>")
	)
	(segment
		(start 68.373752 -224.113852)
		(end 68.373752 -223.740218)
		(width 0.18288)
		(layer "In2.Cu")
		(net "M_A_CPU1_SB_DQ<7>")
	)
	(segment
		(start 69.979032 -224.306892)
		(end 69.785992 -224.113852)
		(width 0.18288)
		(layer "In2.Cu")
		(net "M_A_CPU1_SB_DQ<7>")
	)
	(segment
		(start 68.373752 -223.740218)
		(end 68.163186 -223.529652)
		(width 0.18288)
		(layer "In2.Cu")
		(net "M_A_CPU1_SB_DQ<7>")
	)
	(segment
		(start 68.566792 -224.306892)
		(end 68.373752 -224.113852)
		(width 0.18288)
		(layer "In2.Cu")
		(net "M_A_CPU1_SB_DQ<7>")
	)
	(segment
		(start 68.163186 -223.529652)
		(end 67.860672 -223.529652)
		(width 0.18288)
		(layer "In2.Cu")
		(net "M_A_CPU1_SB_DQ<7>")
	)
	(segment
		(start 67.667632 -223.722692)
		(end 67.667632 -224.113852)
		(width 0.18288)
		(layer "In2.Cu")
		(net "M_A_CPU1_SB_DQ<7>")
	)
	(segment
		(start 69.592952 -223.529652)
		(end 69.272912 -223.529652)
		(width 0.18288)
		(layer "In2.Cu")
		(net "M_A_CPU1_SB_DQ<7>")
	)
	(segment
		(start 69.272912 -223.529652)
		(end 69.079872 -223.722692)
		(width 0.18288)
		(layer "In2.Cu")
		(net "M_A_CPU1_SB_DQ<7>")
	)
	(segment
		(start 66.897758 -224.160334)
		(end 66.897758 -223.73463)
		(width 0.18288)
		(layer "In2.Cu")
		(net "M_A_CPU1_SB_DQ<7>")
	)
	(segment
		(start 83.592162 -235.530898)
		(end 82.759296 -235.530898)
		(width 0.088646)
		(layer "In2.Cu")
		(net "M_A_CPU1_SB_DQ<7>")
	)
	(segment
		(start 89.711784 -235.783882)
		(end 89.64676 -235.718858)
		(width 0.088646)
		(layer "In2.Cu")
		(net "M_A_CPU1_SB_DQ<7>")
	)
	(segment
		(start 86.548214 -235.294424)
		(end 86.533482 -235.285788)
		(width 0.088646)
		(layer "In2.Cu")
		(net "M_A_CPU1_SB_DQ<7>")
	)
	(segment
		(start 81.825592 -235.530898)
		(end 70.601586 -224.306892)
		(width 0.18288)
		(layer "In2.Cu")
		(net "M_A_CPU1_SB_DQ<7>")
	)
	(segment
		(start 87.488014 -235.294424)
		(end 87.473282 -235.285788)
		(width 0.088646)
		(layer "In2.Cu")
		(net "M_A_CPU1_SB_DQ<7>")
	)
	(segment
		(start 90.024966 -235.783882)
		(end 89.711784 -235.783882)
		(width 0.088646)
		(layer "In2.Cu")
		(net "M_A_CPU1_SB_DQ<7>")
	)
	(segment
		(start 83.98637 -235.384086)
		(end 83.834478 -235.535978)
		(width 0.088646)
		(layer "In2.Cu")
		(net "M_A_CPU1_SB_DQ<7>")
	)
	(segment
		(start 69.079872 -223.722692)
		(end 69.079872 -224.113852)
		(width 0.18288)
		(layer "In2.Cu")
		(net "M_A_CPU1_SB_DQ<7>")
	)
	(segment
		(start 68.886832 -224.306892)
		(end 68.566792 -224.306892)
		(width 0.18288)
		(layer "In2.Cu")
		(net "M_A_CPU1_SB_DQ<7>")
	)
	(segment
		(start 69.079872 -224.113852)
		(end 68.886832 -224.306892)
		(width 0.18288)
		(layer "In2.Cu")
		(net "M_A_CPU1_SB_DQ<7>")
	)
	(segment
		(start 82.759296 -235.530898)
		(end 81.825592 -235.530898)
		(width 0.18288)
		(layer "In2.Cu")
		(net "M_A_CPU1_SB_DQ<7>")
	)
	(segment
		(start 84.668614 -235.294424)
		(end 84.653882 -235.285788)
		(width 0.088646)
		(layer "In2.Cu")
		(net "M_A_CPU1_SB_DQ<7>")
	)
	(segment
		(start 67.860672 -223.529652)
		(end 67.667632 -223.722692)
		(width 0.18288)
		(layer "In2.Cu")
		(net "M_A_CPU1_SB_DQ<7>")
	)
	(segment
		(start 83.834478 -235.535978)
		(end 83.597242 -235.535978)
		(width 0.088646)
		(layer "In2.Cu")
		(net "M_A_CPU1_SB_DQ<7>")
	)
	(segment
		(start 67.474592 -224.306892)
		(end 67.044316 -224.306892)
		(width 0.18288)
		(layer "In2.Cu")
		(net "M_A_CPU1_SB_DQ<7>")
	)
	(segment
		(start 66.482722 -223.529652)
		(end 66.152014 -223.666558)
		(width 0.18288)
		(layer "In2.Cu")
		(net "M_A_CPU1_SB_DQ<7>")
	)
	(segment
		(start 83.597242 -235.535978)
		(end 83.592162 -235.530898)
		(width 0.088646)
		(layer "In2.Cu")
		(net "M_A_CPU1_SB_DQ<7>")
	)
	(arc
		(start 84.10321 -235.294424)
		(mid 84.04187 -235.335448)
		(end 83.98637 -235.384086)
		(width 0.088646)
		(layer "In2.Cu")
		(net "M_A_CPU1_SB_DQ<7>")
	)
	(arc
		(start 87.86241 -235.294424)
		(mid 87.675212 -235.344567)
		(end 87.488014 -235.294424)
		(width 0.088646)
		(layer "In2.Cu")
		(net "M_A_CPU1_SB_DQ<7>")
	)
	(arc
		(start 89.64676 -235.718858)
		(mid 89.557606 -235.473371)
		(end 89.367614 -235.29417)
		(width 0.088646)
		(layer "In2.Cu")
		(net "M_A_CPU1_SB_DQ<7>")
	)
	(arc
		(start 86.533482 -235.285788)
		(mid 86.257007 -235.218468)
		(end 85.98281 -235.294424)
		(width 0.088646)
		(layer "In2.Cu")
		(net "M_A_CPU1_SB_DQ<7>")
	)
	(arc
		(start 84.653882 -235.285788)
		(mid 84.377407 -235.218468)
		(end 84.10321 -235.294424)
		(width 0.088646)
		(layer "In2.Cu")
		(net "M_A_CPU1_SB_DQ<7>")
	)
	(arc
		(start 85.98281 -235.294424)
		(mid 85.795612 -235.344567)
		(end 85.608414 -235.294424)
		(width 0.088646)
		(layer "In2.Cu")
		(net "M_A_CPU1_SB_DQ<7>")
	)
	(arc
		(start 88.413082 -235.285788)
		(mid 88.136607 -235.218468)
		(end 87.86241 -235.294424)
		(width 0.088646)
		(layer "In2.Cu")
		(net "M_A_CPU1_SB_DQ<7>")
	)
	(arc
		(start 85.593682 -235.285788)
		(mid 85.317207 -235.218468)
		(end 85.04301 -235.294424)
		(width 0.088646)
		(layer "In2.Cu")
		(net "M_A_CPU1_SB_DQ<7>")
	)
	(arc
		(start 86.92261 -235.294424)
		(mid 86.735412 -235.344567)
		(end 86.548214 -235.294424)
		(width 0.088646)
		(layer "In2.Cu")
		(net "M_A_CPU1_SB_DQ<7>")
	)
	(arc
		(start 89.352882 -235.285788)
		(mid 89.076407 -235.218468)
		(end 88.80221 -235.294424)
		(width 0.088646)
		(layer "In2.Cu")
		(net "M_A_CPU1_SB_DQ<7>")
	)
	(arc
		(start 88.80221 -235.294424)
		(mid 88.615012 -235.344567)
		(end 88.427814 -235.294424)
		(width 0.088646)
		(layer "In2.Cu")
		(net "M_A_CPU1_SB_DQ<7>")
	)
	(arc
		(start 87.473282 -235.285788)
		(mid 87.196807 -235.218468)
		(end 86.92261 -235.294424)
		(width 0.088646)
		(layer "In2.Cu")
		(net "M_A_CPU1_SB_DQ<7>")
	)
	(arc
		(start 85.04301 -235.294424)
		(mid 84.855812 -235.344567)
		(end 84.668614 -235.294424)
		(width 0.088646)
		(layer "In2.Cu")
		(net "M_A_CPU1_SB_DQ<7>")
	)
	(segment
		(start 59.913012 -225.791776)
		(end 59.891422 -225.791776)
		(width 0.101854)
		(layer "F.Cu")
		(net "M_A_CPU1_SB_DQ<6>")
	)
	(segment
		(start 59.10199 -225.36658)
		(end 57.503314 -225.36658)
		(width 0.20066)
		(layer "F.Cu")
		(net "M_A_CPU1_SB_DQ<6>")
	)
	(segment
		(start 62.669928 -225.664268)
		(end 62.54242 -225.791776)
		(width 0.20066)
		(layer "F.Cu")
		(net "M_A_CPU1_SB_DQ<6>")
	)
	(segment
		(start 62.669928 -225.3107)
		(end 62.669928 -225.664268)
		(width 0.20066)
		(layer "F.Cu")
		(net "M_A_CPU1_SB_DQ<6>")
	)
	(segment
		(start 59.822842 -225.808794)
		(end 59.54522 -225.808794)
		(width 0.20066)
		(layer "F.Cu")
		(net "M_A_CPU1_SB_DQ<6>")
	)
	(segment
		(start 63.329312 -225.144838)
		(end 62.83579 -225.144838)
		(width 0.20066)
		(layer "F.Cu")
		(net "M_A_CPU1_SB_DQ<6>")
	)
	(segment
		(start 90.494612 -237.133638)
		(end 90.494612 -236.597952)
		(width 0.20066)
		(layer "F.Cu")
		(net "M_A_CPU1_SB_DQ<6>")
	)
	(segment
		(start 59.54522 -225.808794)
		(end 59.102498 -225.366072)
		(width 0.20066)
		(layer "F.Cu")
		(net "M_A_CPU1_SB_DQ<6>")
	)
	(segment
		(start 59.102498 -225.366072)
		(end 59.10199 -225.36658)
		(width 0.20066)
		(layer "F.Cu")
		(net "M_A_CPU1_SB_DQ<6>")
	)
	(segment
		(start 66.152014 -225.36658)
		(end 65.047114 -225.36658)
		(width 0.20066)
		(layer "F.Cu")
		(net "M_A_CPU1_SB_DQ<6>")
	)
	(segment
		(start 59.874404 -225.808794)
		(end 59.822842 -225.808794)
		(width 0.101854)
		(layer "F.Cu")
		(net "M_A_CPU1_SB_DQ<6>")
	)
	(segment
		(start 63.551054 -225.36658)
		(end 63.329312 -225.144838)
		(width 0.20066)
		(layer "F.Cu")
		(net "M_A_CPU1_SB_DQ<6>")
	)
	(segment
		(start 62.83579 -225.144838)
		(end 62.669928 -225.3107)
		(width 0.20066)
		(layer "F.Cu")
		(net "M_A_CPU1_SB_DQ<6>")
	)
	(segment
		(start 62.54242 -225.791776)
		(end 62.147958 -225.791776)
		(width 0.20066)
		(layer "F.Cu")
		(net "M_A_CPU1_SB_DQ<6>")
	)
	(segment
		(start 65.047114 -225.36658)
		(end 63.551054 -225.36658)
		(width 0.20066)
		(layer "F.Cu")
		(net "M_A_CPU1_SB_DQ<6>")
	)
	(segment
		(start 59.891422 -225.791776)
		(end 59.874404 -225.808794)
		(width 0.101854)
		(layer "F.Cu")
		(net "M_A_CPU1_SB_DQ<6>")
	)
	(segment
		(start 62.147958 -225.791776)
		(end 62.072012 -225.791776)
		(width 0.101854)
		(layer "F.Cu")
		(net "M_A_CPU1_SB_DQ<6>")
	)
	(segment
		(start 62.072012 -225.791776)
		(end 59.913012 -225.791776)
		(width 0.1016)
		(layer "F.Cu")
		(net "M_A_CPU1_SB_DQ<6>")
	)
	(segment
		(start 90.494866 -237.133892)
		(end 90.494612 -237.133638)
		(width 0.20066)
		(layer "F.Cu")
		(net "M_A_CPU1_SB_DQ<6>")
	)
	(segment
		(start 68.729606 -225.437192)
		(end 68.409566 -225.437192)
		(width 0.18288)
		(layer "In2.Cu")
		(net "M_A_CPU1_SB_DQ<6>")
	)
	(segment
		(start 90.181938 -236.597952)
		(end 90.116406 -236.53242)
		(width 0.088646)
		(layer "In2.Cu")
		(net "M_A_CPU1_SB_DQ<6>")
	)
	(segment
		(start 87.974932 -236.117892)
		(end 87.957914 -236.10824)
		(width 0.088646)
		(layer "In2.Cu")
		(net "M_A_CPU1_SB_DQ<6>")
	)
	(segment
		(start 69.435726 -226.288854)
		(end 69.115686 -226.288854)
		(width 0.18288)
		(layer "In2.Cu")
		(net "M_A_CPU1_SB_DQ<6>")
	)
	(segment
		(start 67.48653 -225.55962)
		(end 67.29349 -225.36658)
		(width 0.18288)
		(layer "In2.Cu")
		(net "M_A_CPU1_SB_DQ<6>")
	)
	(segment
		(start 68.023486 -226.288854)
		(end 67.67957 -226.288854)
		(width 0.18288)
		(layer "In2.Cu")
		(net "M_A_CPU1_SB_DQ<6>")
	)
	(segment
		(start 82.759296 -236.221778)
		(end 81.05902 -236.221778)
		(width 0.18288)
		(layer "In2.Cu")
		(net "M_A_CPU1_SB_DQ<6>")
	)
	(segment
		(start 67.29349 -225.36658)
		(end 66.152014 -225.36658)
		(width 0.18288)
		(layer "In2.Cu")
		(net "M_A_CPU1_SB_DQ<6>")
	)
	(segment
		(start 67.48653 -226.095814)
		(end 67.48653 -225.55962)
		(width 0.18288)
		(layer "In2.Cu")
		(net "M_A_CPU1_SB_DQ<6>")
	)
	(segment
		(start 71.126096 -226.288854)
		(end 70.527926 -226.288854)
		(width 0.18288)
		(layer "In2.Cu")
		(net "M_A_CPU1_SB_DQ<6>")
	)
	(segment
		(start 70.527926 -226.288854)
		(end 70.334886 -226.095814)
		(width 0.18288)
		(layer "In2.Cu")
		(net "M_A_CPU1_SB_DQ<6>")
	)
	(segment
		(start 68.216526 -226.095814)
		(end 68.023486 -226.288854)
		(width 0.18288)
		(layer "In2.Cu")
		(net "M_A_CPU1_SB_DQ<6>")
	)
	(segment
		(start 84.091526 -236.09808)
		(end 83.76158 -236.09808)
		(width 0.088646)
		(layer "In2.Cu")
		(net "M_A_CPU1_SB_DQ<6>")
	)
	(segment
		(start 90.494612 -236.597952)
		(end 90.181938 -236.597952)
		(width 0.088646)
		(layer "In2.Cu")
		(net "M_A_CPU1_SB_DQ<6>")
	)
	(segment
		(start 69.628766 -225.617024)
		(end 69.628766 -226.095814)
		(width 0.18288)
		(layer "In2.Cu")
		(net "M_A_CPU1_SB_DQ<6>")
	)
	(segment
		(start 81.05902 -236.221778)
		(end 71.126096 -226.288854)
		(width 0.18288)
		(layer "In2.Cu")
		(net "M_A_CPU1_SB_DQ<6>")
	)
	(segment
		(start 69.821806 -225.423984)
		(end 69.628766 -225.617024)
		(width 0.18288)
		(layer "In2.Cu")
		(net "M_A_CPU1_SB_DQ<6>")
	)
	(segment
		(start 68.922646 -225.630232)
		(end 68.729606 -225.437192)
		(width 0.18288)
		(layer "In2.Cu")
		(net "M_A_CPU1_SB_DQ<6>")
	)
	(segment
		(start 68.216526 -225.630232)
		(end 68.216526 -226.095814)
		(width 0.18288)
		(layer "In2.Cu")
		(net "M_A_CPU1_SB_DQ<6>")
	)
	(segment
		(start 67.67957 -226.288854)
		(end 67.48653 -226.095814)
		(width 0.18288)
		(layer "In2.Cu")
		(net "M_A_CPU1_SB_DQ<6>")
	)
	(segment
		(start 69.115686 -226.288854)
		(end 68.922646 -226.095814)
		(width 0.18288)
		(layer "In2.Cu")
		(net "M_A_CPU1_SB_DQ<6>")
	)
	(segment
		(start 83.637882 -236.221778)
		(end 82.759296 -236.221778)
		(width 0.088646)
		(layer "In2.Cu")
		(net "M_A_CPU1_SB_DQ<6>")
	)
	(segment
		(start 85.51291 -236.10824)
		(end 85.513164 -236.10824)
		(width 0.088646)
		(layer "In2.Cu")
		(net "M_A_CPU1_SB_DQ<6>")
	)
	(segment
		(start 70.334886 -226.095814)
		(end 70.334886 -225.617024)
		(width 0.18288)
		(layer "In2.Cu")
		(net "M_A_CPU1_SB_DQ<6>")
	)
	(segment
		(start 70.334886 -225.617024)
		(end 70.141846 -225.423984)
		(width 0.18288)
		(layer "In2.Cu")
		(net "M_A_CPU1_SB_DQ<6>")
	)
	(segment
		(start 68.409566 -225.437192)
		(end 68.216526 -225.630232)
		(width 0.18288)
		(layer "In2.Cu")
		(net "M_A_CPU1_SB_DQ<6>")
	)
	(segment
		(start 69.628766 -226.095814)
		(end 69.435726 -226.288854)
		(width 0.18288)
		(layer "In2.Cu")
		(net "M_A_CPU1_SB_DQ<6>")
	)
	(segment
		(start 83.76158 -236.09808)
		(end 83.637882 -236.221778)
		(width 0.088646)
		(layer "In2.Cu")
		(net "M_A_CPU1_SB_DQ<6>")
	)
	(segment
		(start 88.33231 -236.108494)
		(end 88.318848 -236.116114)
		(width 0.088646)
		(layer "In2.Cu")
		(net "M_A_CPU1_SB_DQ<6>")
	)
	(segment
		(start 70.141846 -225.423984)
		(end 69.821806 -225.423984)
		(width 0.18288)
		(layer "In2.Cu")
		(net "M_A_CPU1_SB_DQ<6>")
	)
	(segment
		(start 68.922646 -226.095814)
		(end 68.922646 -225.630232)
		(width 0.18288)
		(layer "In2.Cu")
		(net "M_A_CPU1_SB_DQ<6>")
	)
	(arc
		(start 87.018114 -236.10824)
		(mid 86.735412 -236.032464)
		(end 86.45271 -236.10824)
		(width 0.088646)
		(layer "In2.Cu")
		(net "M_A_CPU1_SB_DQ<6>")
	)
	(arc
		(start 87.39251 -236.10824)
		(mid 87.205312 -236.158383)
		(end 87.018114 -236.10824)
		(width 0.088646)
		(layer "In2.Cu")
		(net "M_A_CPU1_SB_DQ<6>")
	)
	(arc
		(start 86.45271 -236.10824)
		(mid 86.265512 -236.158383)
		(end 86.078314 -236.10824)
		(width 0.088646)
		(layer "In2.Cu")
		(net "M_A_CPU1_SB_DQ<6>")
	)
	(arc
		(start 90.116406 -236.53242)
		(mid 89.80857 -236.09269)
		(end 89.27211 -236.108494)
		(width 0.088646)
		(layer "In2.Cu")
		(net "M_A_CPU1_SB_DQ<6>")
	)
	(arc
		(start 89.27211 -236.108494)
		(mid 89.084912 -236.158637)
		(end 88.897714 -236.108494)
		(width 0.088646)
		(layer "In2.Cu")
		(net "M_A_CPU1_SB_DQ<6>")
	)
	(arc
		(start 85.138768 -236.10824)
		(mid 84.856066 -236.032498)
		(end 84.573364 -236.10824)
		(width 0.088646)
		(layer "In2.Cu")
		(net "M_A_CPU1_SB_DQ<6>")
	)
	(arc
		(start 84.238846 -236.128306)
		(mid 84.166718 -236.10573)
		(end 84.091526 -236.09808)
		(width 0.088646)
		(layer "In2.Cu")
		(net "M_A_CPU1_SB_DQ<6>")
	)
	(arc
		(start 88.318848 -236.116114)
		(mid 88.14713 -236.162526)
		(end 87.974932 -236.117892)
		(width 0.088646)
		(layer "In2.Cu")
		(net "M_A_CPU1_SB_DQ<6>")
	)
	(arc
		(start 88.897714 -236.108494)
		(mid 88.615012 -236.032718)
		(end 88.33231 -236.108494)
		(width 0.088646)
		(layer "In2.Cu")
		(net "M_A_CPU1_SB_DQ<6>")
	)
	(arc
		(start 86.078314 -236.10824)
		(mid 85.795612 -236.032464)
		(end 85.51291 -236.10824)
		(width 0.088646)
		(layer "In2.Cu")
		(net "M_A_CPU1_SB_DQ<6>")
	)
	(arc
		(start 84.573364 -236.10824)
		(mid 84.408484 -236.157718)
		(end 84.238846 -236.128306)
		(width 0.088646)
		(layer "In2.Cu")
		(net "M_A_CPU1_SB_DQ<6>")
	)
	(arc
		(start 87.957914 -236.10824)
		(mid 87.675212 -236.032464)
		(end 87.39251 -236.10824)
		(width 0.088646)
		(layer "In2.Cu")
		(net "M_A_CPU1_SB_DQ<6>")
	)
	(arc
		(start 85.513164 -236.10824)
		(mid 85.325966 -236.158383)
		(end 85.138768 -236.10824)
		(width 0.088646)
		(layer "In2.Cu")
		(net "M_A_CPU1_SB_DQ<6>")
	)
	(segment
		(start 54.939692 -224.74301)
		(end 54.713378 -224.516696)
		(width 0.20066)
		(layer "F.Cu")
		(net "M_A_CPU1_SB_DQ<5>")
	)
	(segment
		(start 56.610758 -224.0915)
		(end 56.38546 -224.0915)
		(width 0.101854)
		(layer "F.Cu")
		(net "M_A_CPU1_SB_DQ<5>")
	)
	(segment
		(start 58.857896 -224.0915)
		(end 58.704226 -224.0915)
		(width 0.20066)
		(layer "F.Cu")
		(net "M_A_CPU1_SB_DQ<5>")
	)
	(segment
		(start 89.084912 -236.319822)
		(end 89.085166 -236.319568)
		(width 0.20066)
		(layer "F.Cu")
		(net "M_A_CPU1_SB_DQ<5>")
	)
	(segment
		(start 54.713378 -224.516696)
		(end 53.403246 -224.516696)
		(width 0.20066)
		(layer "F.Cu")
		(net "M_A_CPU1_SB_DQ<5>")
	)
	(segment
		(start 56.38546 -224.0915)
		(end 56.37911 -224.08515)
		(width 0.101854)
		(layer "F.Cu")
		(net "M_A_CPU1_SB_DQ<5>")
	)
	(segment
		(start 58.349134 -224.0915)
		(end 56.610758 -224.0915)
		(width 0.1016)
		(layer "F.Cu")
		(net "M_A_CPU1_SB_DQ<5>")
	)
	(segment
		(start 62.051946 -224.516696)
		(end 60.947046 -224.516696)
		(width 0.20066)
		(layer "F.Cu")
		(net "M_A_CPU1_SB_DQ<5>")
	)
	(segment
		(start 89.085166 -236.319568)
		(end 89.085166 -235.783882)
		(width 0.20066)
		(layer "F.Cu")
		(net "M_A_CPU1_SB_DQ<5>")
	)
	(segment
		(start 59.283092 -224.516696)
		(end 58.857896 -224.0915)
		(width 0.20066)
		(layer "F.Cu")
		(net "M_A_CPU1_SB_DQ<5>")
	)
	(segment
		(start 55.583328 -224.246186)
		(end 55.583328 -224.56775)
		(width 0.20066)
		(layer "F.Cu")
		(net "M_A_CPU1_SB_DQ<5>")
	)
	(segment
		(start 55.408068 -224.74301)
		(end 54.939692 -224.74301)
		(width 0.20066)
		(layer "F.Cu")
		(net "M_A_CPU1_SB_DQ<5>")
	)
	(segment
		(start 55.583328 -224.56775)
		(end 55.408068 -224.74301)
		(width 0.20066)
		(layer "F.Cu")
		(net "M_A_CPU1_SB_DQ<5>")
	)
	(segment
		(start 58.704226 -224.0915)
		(end 58.349134 -224.0915)
		(width 0.101854)
		(layer "F.Cu")
		(net "M_A_CPU1_SB_DQ<5>")
	)
	(segment
		(start 56.37911 -224.08515)
		(end 55.744364 -224.08515)
		(width 0.20066)
		(layer "F.Cu")
		(net "M_A_CPU1_SB_DQ<5>")
	)
	(segment
		(start 55.744364 -224.08515)
		(end 55.583328 -224.246186)
		(width 0.20066)
		(layer "F.Cu")
		(net "M_A_CPU1_SB_DQ<5>")
	)
	(segment
		(start 60.947046 -224.516696)
		(end 59.283092 -224.516696)
		(width 0.20066)
		(layer "F.Cu")
		(net "M_A_CPU1_SB_DQ<5>")
	)
	(segment
		(start 89.27846 -235.46308)
		(end 89.272364 -235.459524)
		(width 0.088646)
		(layer "In2.Cu")
		(net "M_A_CPU1_SB_DQ<5>")
	)
	(segment
		(start 85.527896 -235.46816)
		(end 85.513164 -235.459524)
		(width 0.088646)
		(layer "In2.Cu")
		(net "M_A_CPU1_SB_DQ<5>")
	)
	(segment
		(start 86.467696 -235.46816)
		(end 86.452964 -235.459524)
		(width 0.088646)
		(layer "In2.Cu")
		(net "M_A_CPU1_SB_DQ<5>")
	)
	(segment
		(start 66.437002 -224.841054)
		(end 66.336418 -224.941638)
		(width 0.18288)
		(layer "In2.Cu")
		(net "M_A_CPU1_SB_DQ<5>")
	)
	(segment
		(start 84.588096 -235.46816)
		(end 84.573364 -235.459524)
		(width 0.088646)
		(layer "In2.Cu")
		(net "M_A_CPU1_SB_DQ<5>")
	)
	(segment
		(start 89.085166 -235.783882)
		(end 89.39784 -235.783882)
		(width 0.088646)
		(layer "In2.Cu")
		(net "M_A_CPU1_SB_DQ<5>")
	)
	(segment
		(start 63.982092 -225.162364)
		(end 62.697614 -225.162364)
		(width 0.18288)
		(layer "In2.Cu")
		(net "M_A_CPU1_SB_DQ<5>")
	)
	(segment
		(start 87.407496 -235.46816)
		(end 87.392764 -235.459524)
		(width 0.088646)
		(layer "In2.Cu")
		(net "M_A_CPU1_SB_DQ<5>")
	)
	(segment
		(start 70.407276 -224.841054)
		(end 66.437002 -224.841054)
		(width 0.18288)
		(layer "In2.Cu")
		(net "M_A_CPU1_SB_DQ<5>")
	)
	(segment
		(start 64.202818 -224.941638)
		(end 63.982092 -225.162364)
		(width 0.18288)
		(layer "In2.Cu")
		(net "M_A_CPU1_SB_DQ<5>")
	)
	(segment
		(start 89.39784 -235.783882)
		(end 89.45499 -235.726732)
		(width 0.088646)
		(layer "In2.Cu")
		(net "M_A_CPU1_SB_DQ<5>")
	)
	(segment
		(start 62.697614 -225.162364)
		(end 62.051946 -224.516696)
		(width 0.18288)
		(layer "In2.Cu")
		(net "M_A_CPU1_SB_DQ<5>")
	)
	(segment
		(start 89.281 -235.464604)
		(end 89.27846 -235.46308)
		(width 0.088646)
		(layer "In2.Cu")
		(net "M_A_CPU1_SB_DQ<5>")
	)
	(segment
		(start 83.676236 -235.726224)
		(end 83.526122 -235.876338)
		(width 0.088646)
		(layer "In2.Cu")
		(net "M_A_CPU1_SB_DQ<5>")
	)
	(segment
		(start 88.347296 -235.46816)
		(end 88.332564 -235.459524)
		(width 0.088646)
		(layer "In2.Cu")
		(net "M_A_CPU1_SB_DQ<5>")
	)
	(segment
		(start 82.759296 -235.876338)
		(end 81.44256 -235.876338)
		(width 0.18288)
		(layer "In2.Cu")
		(net "M_A_CPU1_SB_DQ<5>")
	)
	(segment
		(start 83.526122 -235.876338)
		(end 82.759296 -235.876338)
		(width 0.088646)
		(layer "In2.Cu")
		(net "M_A_CPU1_SB_DQ<5>")
	)
	(segment
		(start 83.913472 -235.726224)
		(end 83.676236 -235.726224)
		(width 0.088646)
		(layer "In2.Cu")
		(net "M_A_CPU1_SB_DQ<5>")
	)
	(segment
		(start 66.336418 -224.941638)
		(end 64.202818 -224.941638)
		(width 0.18288)
		(layer "In2.Cu")
		(net "M_A_CPU1_SB_DQ<5>")
	)
	(segment
		(start 84.12099 -235.518706)
		(end 83.913472 -235.726224)
		(width 0.088646)
		(layer "In2.Cu")
		(net "M_A_CPU1_SB_DQ<5>")
	)
	(segment
		(start 81.44256 -235.876338)
		(end 70.407276 -224.841054)
		(width 0.18288)
		(layer "In2.Cu")
		(net "M_A_CPU1_SB_DQ<5>")
	)
	(arc
		(start 87.958168 -235.459524)
		(mid 87.683969 -235.535359)
		(end 87.407496 -235.46816)
		(width 0.088646)
		(layer "In2.Cu")
		(net "M_A_CPU1_SB_DQ<5>")
	)
	(arc
		(start 86.452964 -235.459524)
		(mid 86.265766 -235.409381)
		(end 86.078568 -235.459524)
		(width 0.088646)
		(layer "In2.Cu")
		(net "M_A_CPU1_SB_DQ<5>")
	)
	(arc
		(start 84.198968 -235.459524)
		(mid 84.158038 -235.486557)
		(end 84.12099 -235.518706)
		(width 0.088646)
		(layer "In2.Cu")
		(net "M_A_CPU1_SB_DQ<5>")
	)
	(arc
		(start 89.272364 -235.459524)
		(mid 89.085166 -235.409381)
		(end 88.897968 -235.459524)
		(width 0.088646)
		(layer "In2.Cu")
		(net "M_A_CPU1_SB_DQ<5>")
	)
	(arc
		(start 88.897968 -235.459524)
		(mid 88.623769 -235.535359)
		(end 88.347296 -235.46816)
		(width 0.088646)
		(layer "In2.Cu")
		(net "M_A_CPU1_SB_DQ<5>")
	)
	(arc
		(start 87.392764 -235.459524)
		(mid 87.205566 -235.409381)
		(end 87.018368 -235.459524)
		(width 0.088646)
		(layer "In2.Cu")
		(net "M_A_CPU1_SB_DQ<5>")
	)
	(arc
		(start 85.138768 -235.459524)
		(mid 84.864569 -235.535359)
		(end 84.588096 -235.46816)
		(width 0.088646)
		(layer "In2.Cu")
		(net "M_A_CPU1_SB_DQ<5>")
	)
	(arc
		(start 88.332564 -235.459524)
		(mid 88.145366 -235.409381)
		(end 87.958168 -235.459524)
		(width 0.088646)
		(layer "In2.Cu")
		(net "M_A_CPU1_SB_DQ<5>")
	)
	(arc
		(start 85.513164 -235.459524)
		(mid 85.325966 -235.409381)
		(end 85.138768 -235.459524)
		(width 0.088646)
		(layer "In2.Cu")
		(net "M_A_CPU1_SB_DQ<5>")
	)
	(arc
		(start 86.078568 -235.459524)
		(mid 85.804369 -235.535359)
		(end 85.527896 -235.46816)
		(width 0.088646)
		(layer "In2.Cu")
		(net "M_A_CPU1_SB_DQ<5>")
	)
	(arc
		(start 84.573364 -235.459524)
		(mid 84.386166 -235.409381)
		(end 84.198968 -235.459524)
		(width 0.088646)
		(layer "In2.Cu")
		(net "M_A_CPU1_SB_DQ<5>")
	)
	(arc
		(start 87.018368 -235.459524)
		(mid 86.744169 -235.535359)
		(end 86.467696 -235.46816)
		(width 0.088646)
		(layer "In2.Cu")
		(net "M_A_CPU1_SB_DQ<5>")
	)
	(arc
		(start 89.45499 -235.726732)
		(mid 89.396871 -235.576491)
		(end 89.281 -235.464604)
		(width 0.088646)
		(layer "In2.Cu")
		(net "M_A_CPU1_SB_DQ<5>")
	)
	(segment
		(start 60.947046 -226.216718)
		(end 59.332876 -226.216718)
		(width 0.20066)
		(layer "F.Cu")
		(net "M_A_CPU1_SB_DQ<4>")
	)
	(segment
		(start 62.051946 -226.216718)
		(end 60.947046 -226.216718)
		(width 0.20066)
		(layer "F.Cu")
		(net "M_A_CPU1_SB_DQ<4>")
	)
	(segment
		(start 54.713378 -226.216718)
		(end 53.403246 -226.216718)
		(width 0.20066)
		(layer "F.Cu")
		(net "M_A_CPU1_SB_DQ<4>")
	)
	(segment
		(start 55.583328 -226.234244)
		(end 55.34914 -226.468432)
		(width 0.20066)
		(layer "F.Cu")
		(net "M_A_CPU1_SB_DQ<4>")
	)
	(segment
		(start 56.384698 -225.791522)
		(end 56.37911 -225.785934)
		(width 0.101854)
		(layer "F.Cu")
		(net "M_A_CPU1_SB_DQ<4>")
	)
	(segment
		(start 55.743602 -225.785934)
		(end 55.583328 -225.946208)
		(width 0.20066)
		(layer "F.Cu")
		(net "M_A_CPU1_SB_DQ<4>")
	)
	(segment
		(start 55.583328 -225.946208)
		(end 55.583328 -226.234244)
		(width 0.20066)
		(layer "F.Cu")
		(net "M_A_CPU1_SB_DQ<4>")
	)
	(segment
		(start 58.330592 -225.791522)
		(end 56.610758 -225.791522)
		(width 0.1016)
		(layer "F.Cu")
		(net "M_A_CPU1_SB_DQ<4>")
	)
	(segment
		(start 88.615266 -237.133892)
		(end 88.615266 -236.597952)
		(width 0.20066)
		(layer "F.Cu")
		(net "M_A_CPU1_SB_DQ<4>")
	)
	(segment
		(start 54.965092 -226.468432)
		(end 54.713378 -226.216718)
		(width 0.20066)
		(layer "F.Cu")
		(net "M_A_CPU1_SB_DQ<4>")
	)
	(segment
		(start 58.704226 -225.791522)
		(end 58.330592 -225.791522)
		(width 0.101854)
		(layer "F.Cu")
		(net "M_A_CPU1_SB_DQ<4>")
	)
	(segment
		(start 59.332876 -226.216718)
		(end 58.90768 -225.791522)
		(width 0.20066)
		(layer "F.Cu")
		(net "M_A_CPU1_SB_DQ<4>")
	)
	(segment
		(start 56.610758 -225.791522)
		(end 56.384698 -225.791522)
		(width 0.101854)
		(layer "F.Cu")
		(net "M_A_CPU1_SB_DQ<4>")
	)
	(segment
		(start 56.37911 -225.785934)
		(end 55.743602 -225.785934)
		(width 0.20066)
		(layer "F.Cu")
		(net "M_A_CPU1_SB_DQ<4>")
	)
	(segment
		(start 58.90768 -225.791522)
		(end 58.704226 -225.791522)
		(width 0.20066)
		(layer "F.Cu")
		(net "M_A_CPU1_SB_DQ<4>")
	)
	(segment
		(start 55.34914 -226.468432)
		(end 54.965092 -226.468432)
		(width 0.20066)
		(layer "F.Cu")
		(net "M_A_CPU1_SB_DQ<4>")
	)
	(segment
		(start 62.670944 -226.609402)
		(end 62.44463 -226.609402)
		(width 0.18288)
		(layer "In2.Cu")
		(net "M_A_CPU1_SB_DQ<4>")
	)
	(segment
		(start 83.597496 -236.567218)
		(end 82.759296 -236.567218)
		(width 0.088646)
		(layer "In2.Cu")
		(net "M_A_CPU1_SB_DQ<4>")
	)
	(segment
		(start 84.059776 -236.30128)
		(end 83.863434 -236.30128)
		(width 0.088646)
		(layer "In2.Cu")
		(net "M_A_CPU1_SB_DQ<4>")
	)
	(segment
		(start 80.679544 -236.567218)
		(end 70.922134 -226.809808)
		(width 0.18288)
		(layer "In2.Cu")
		(net "M_A_CPU1_SB_DQ<4>")
	)
	(segment
		(start 62.44463 -226.609402)
		(end 62.051946 -226.216718)
		(width 0.18288)
		(layer "In2.Cu")
		(net "M_A_CPU1_SB_DQ<4>")
	)
	(segment
		(start 70.922134 -226.809808)
		(end 67.389502 -226.809808)
		(width 0.18288)
		(layer "In2.Cu")
		(net "M_A_CPU1_SB_DQ<4>")
	)
	(segment
		(start 66.373248 -225.793554)
		(end 64.153034 -225.793554)
		(width 0.18288)
		(layer "In2.Cu")
		(net "M_A_CPU1_SB_DQ<4>")
	)
	(segment
		(start 64.04991 -225.69043)
		(end 63.589916 -225.69043)
		(width 0.18288)
		(layer "In2.Cu")
		(net "M_A_CPU1_SB_DQ<4>")
	)
	(segment
		(start 88.615266 -236.597952)
		(end 88.100662 -236.412024)
		(width 0.088646)
		(layer "In2.Cu")
		(net "M_A_CPU1_SB_DQ<4>")
	)
	(segment
		(start 85.608414 -236.27334)
		(end 85.608668 -236.273594)
		(width 0.088646)
		(layer "In2.Cu")
		(net "M_A_CPU1_SB_DQ<4>")
	)
	(segment
		(start 63.589916 -225.69043)
		(end 62.670944 -226.609402)
		(width 0.18288)
		(layer "In2.Cu")
		(net "M_A_CPU1_SB_DQ<4>")
	)
	(segment
		(start 82.759296 -236.567218)
		(end 80.679544 -236.567218)
		(width 0.18288)
		(layer "In2.Cu")
		(net "M_A_CPU1_SB_DQ<4>")
	)
	(segment
		(start 64.153034 -225.793554)
		(end 64.04991 -225.69043)
		(width 0.18288)
		(layer "In2.Cu")
		(net "M_A_CPU1_SB_DQ<4>")
	)
	(segment
		(start 83.863434 -236.30128)
		(end 83.597496 -236.567218)
		(width 0.088646)
		(layer "In2.Cu")
		(net "M_A_CPU1_SB_DQ<4>")
	)
	(segment
		(start 88.100662 -236.412024)
		(end 87.86241 -236.27334)
		(width 0.088646)
		(layer "In2.Cu")
		(net "M_A_CPU1_SB_DQ<4>")
	)
	(segment
		(start 67.389502 -226.809808)
		(end 66.373248 -225.793554)
		(width 0.18288)
		(layer "In2.Cu")
		(net "M_A_CPU1_SB_DQ<4>")
	)
	(arc
		(start 85.608668 -236.273594)
		(mid 85.325966 -236.349336)
		(end 85.043264 -236.273594)
		(width 0.088646)
		(layer "In2.Cu")
		(net "M_A_CPU1_SB_DQ<4>")
	)
	(arc
		(start 86.548214 -236.27334)
		(mid 86.265512 -236.349116)
		(end 85.98281 -236.27334)
		(width 0.088646)
		(layer "In2.Cu")
		(net "M_A_CPU1_SB_DQ<4>")
	)
	(arc
		(start 84.222844 -236.32541)
		(mid 84.142193 -236.307383)
		(end 84.059776 -236.30128)
		(width 0.088646)
		(layer "In2.Cu")
		(net "M_A_CPU1_SB_DQ<4>")
	)
	(arc
		(start 86.92261 -236.27334)
		(mid 86.735412 -236.223197)
		(end 86.548214 -236.27334)
		(width 0.088646)
		(layer "In2.Cu")
		(net "M_A_CPU1_SB_DQ<4>")
	)
	(arc
		(start 84.668868 -236.273594)
		(mid 84.451217 -236.34568)
		(end 84.222844 -236.32541)
		(width 0.088646)
		(layer "In2.Cu")
		(net "M_A_CPU1_SB_DQ<4>")
	)
	(arc
		(start 87.86241 -236.27334)
		(mid 87.675212 -236.223197)
		(end 87.488014 -236.27334)
		(width 0.088646)
		(layer "In2.Cu")
		(net "M_A_CPU1_SB_DQ<4>")
	)
	(arc
		(start 85.98281 -236.27334)
		(mid 85.795612 -236.223197)
		(end 85.608414 -236.27334)
		(width 0.088646)
		(layer "In2.Cu")
		(net "M_A_CPU1_SB_DQ<4>")
	)
	(arc
		(start 87.488014 -236.27334)
		(mid 87.205312 -236.349082)
		(end 86.92261 -236.27334)
		(width 0.088646)
		(layer "In2.Cu")
		(net "M_A_CPU1_SB_DQ<4>")
	)
	(arc
		(start 85.043264 -236.273594)
		(mid 84.856066 -236.223451)
		(end 84.668868 -236.273594)
		(width 0.088646)
		(layer "In2.Cu")
		(net "M_A_CPU1_SB_DQ<4>")
	)
	(segment
		(start 59.111896 -229.616762)
		(end 57.503314 -229.616762)
		(width 0.20066)
		(layer "F.Cu")
		(net "M_A_CPU1_SB_DQ<3>")
	)
	(segment
		(start 59.913012 -230.041704)
		(end 59.873642 -230.041704)
		(width 0.101854)
		(layer "F.Cu")
		(net "M_A_CPU1_SB_DQ<3>")
	)
	(segment
		(start 59.557158 -230.062024)
		(end 59.111896 -229.616762)
		(width 0.20066)
		(layer "F.Cu")
		(net "M_A_CPU1_SB_DQ<3>")
	)
	(segment
		(start 65.047114 -229.616762)
		(end 63.551054 -229.616762)
		(width 0.20066)
		(layer "F.Cu")
		(net "M_A_CPU1_SB_DQ<3>")
	)
	(segment
		(start 90.494866 -238.761524)
		(end 90.494612 -238.225584)
		(width 0.20066)
		(layer "F.Cu")
		(net "M_A_CPU1_SB_DQ<3>")
	)
	(segment
		(start 62.072012 -230.041704)
		(end 59.913012 -230.041704)
		(width 0.1016)
		(layer "F.Cu")
		(net "M_A_CPU1_SB_DQ<3>")
	)
	(segment
		(start 59.873642 -230.041704)
		(end 59.853322 -230.062024)
		(width 0.101854)
		(layer "F.Cu")
		(net "M_A_CPU1_SB_DQ<3>")
	)
	(segment
		(start 62.83579 -229.39502)
		(end 62.669928 -229.560882)
		(width 0.20066)
		(layer "F.Cu")
		(net "M_A_CPU1_SB_DQ<3>")
	)
	(segment
		(start 59.853322 -230.062024)
		(end 59.822842 -230.062024)
		(width 0.101854)
		(layer "F.Cu")
		(net "M_A_CPU1_SB_DQ<3>")
	)
	(segment
		(start 63.551054 -229.616762)
		(end 63.329312 -229.39502)
		(width 0.20066)
		(layer "F.Cu")
		(net "M_A_CPU1_SB_DQ<3>")
	)
	(segment
		(start 62.147958 -230.041704)
		(end 62.072012 -230.041704)
		(width 0.101854)
		(layer "F.Cu")
		(net "M_A_CPU1_SB_DQ<3>")
	)
	(segment
		(start 66.152014 -229.616762)
		(end 65.047114 -229.616762)
		(width 0.20066)
		(layer "F.Cu")
		(net "M_A_CPU1_SB_DQ<3>")
	)
	(segment
		(start 62.542674 -230.041704)
		(end 62.147958 -230.041704)
		(width 0.20066)
		(layer "F.Cu")
		(net "M_A_CPU1_SB_DQ<3>")
	)
	(segment
		(start 62.669928 -229.560882)
		(end 62.669928 -229.91445)
		(width 0.20066)
		(layer "F.Cu")
		(net "M_A_CPU1_SB_DQ<3>")
	)
	(segment
		(start 62.669928 -229.91445)
		(end 62.542674 -230.041704)
		(width 0.20066)
		(layer "F.Cu")
		(net "M_A_CPU1_SB_DQ<3>")
	)
	(segment
		(start 63.329312 -229.39502)
		(end 62.83579 -229.39502)
		(width 0.20066)
		(layer "F.Cu")
		(net "M_A_CPU1_SB_DQ<3>")
	)
	(segment
		(start 59.822842 -230.062024)
		(end 59.557158 -230.062024)
		(width 0.20066)
		(layer "F.Cu")
		(net "M_A_CPU1_SB_DQ<3>")
	)
	(segment
		(start 70.059042 -229.995984)
		(end 70.059042 -230.576374)
		(width 0.18288)
		(layer "In2.Cu")
		(net "M_A_CPU1_SB_DQ<3>")
	)
	(segment
		(start 67.78117 -230.50754)
		(end 67.78117 -229.809802)
		(width 0.18288)
		(layer "In2.Cu")
		(net "M_A_CPU1_SB_DQ<3>")
	)
	(segment
		(start 68.785994 -229.649274)
		(end 68.582794 -229.852474)
		(width 0.18288)
		(layer "In2.Cu")
		(net "M_A_CPU1_SB_DQ<3>")
	)
	(segment
		(start 88.249252 -238.145574)
		(end 88.018874 -238.374936)
		(width 0.088646)
		(layer "In2.Cu")
		(net "M_A_CPU1_SB_DQ<3>")
	)
	(segment
		(start 70.572122 -229.802944)
		(end 70.252082 -229.802944)
		(width 0.18288)
		(layer "In2.Cu")
		(net "M_A_CPU1_SB_DQ<3>")
	)
	(segment
		(start 67.78117 -229.809802)
		(end 67.58813 -229.616762)
		(width 0.18288)
		(layer "In2.Cu")
		(net "M_A_CPU1_SB_DQ<3>")
	)
	(segment
		(start 70.059042 -230.576374)
		(end 69.866002 -230.769414)
		(width 0.18288)
		(layer "In2.Cu")
		(net "M_A_CPU1_SB_DQ<3>")
	)
	(segment
		(start 79.108554 -238.24438)
		(end 71.633588 -230.769414)
		(width 0.18288)
		(layer "In2.Cu")
		(net "M_A_CPU1_SB_DQ<3>")
	)
	(segment
		(start 83.622388 -238.600488)
		(end 83.26628 -238.24438)
		(width 0.088646)
		(layer "In2.Cu")
		(net "M_A_CPU1_SB_DQ<3>")
	)
	(segment
		(start 67.97421 -230.70058)
		(end 67.78117 -230.50754)
		(width 0.18288)
		(layer "In2.Cu")
		(net "M_A_CPU1_SB_DQ<3>")
	)
	(segment
		(start 83.916266 -238.600488)
		(end 83.622388 -238.600488)
		(width 0.088646)
		(layer "In2.Cu")
		(net "M_A_CPU1_SB_DQ<3>")
	)
	(segment
		(start 90.494612 -238.225584)
		(end 90.494358 -238.225838)
		(width 0.088646)
		(layer "In2.Cu")
		(net "M_A_CPU1_SB_DQ<3>")
	)
	(segment
		(start 70.80758 -230.576374)
		(end 70.80758 -230.038402)
		(width 0.18288)
		(layer "In2.Cu")
		(net "M_A_CPU1_SB_DQ<3>")
	)
	(segment
		(start 71.633588 -230.769414)
		(end 71.00062 -230.769414)
		(width 0.18288)
		(layer "In2.Cu")
		(net "M_A_CPU1_SB_DQ<3>")
	)
	(segment
		(start 68.389754 -230.70058)
		(end 67.97421 -230.70058)
		(width 0.18288)
		(layer "In2.Cu")
		(net "M_A_CPU1_SB_DQ<3>")
	)
	(segment
		(start 90.494358 -238.225838)
		(end 90.117168 -238.225838)
		(width 0.088646)
		(layer "In2.Cu")
		(net "M_A_CPU1_SB_DQ<3>")
	)
	(segment
		(start 69.159882 -229.649274)
		(end 68.785994 -229.649274)
		(width 0.18288)
		(layer "In2.Cu")
		(net "M_A_CPU1_SB_DQ<3>")
	)
	(segment
		(start 70.252082 -229.802944)
		(end 70.059042 -229.995984)
		(width 0.18288)
		(layer "In2.Cu")
		(net "M_A_CPU1_SB_DQ<3>")
	)
	(segment
		(start 70.80758 -230.038402)
		(end 70.572122 -229.802944)
		(width 0.18288)
		(layer "In2.Cu")
		(net "M_A_CPU1_SB_DQ<3>")
	)
	(segment
		(start 71.00062 -230.769414)
		(end 70.80758 -230.576374)
		(width 0.18288)
		(layer "In2.Cu")
		(net "M_A_CPU1_SB_DQ<3>")
	)
	(segment
		(start 69.355716 -229.845108)
		(end 69.159882 -229.649274)
		(width 0.18288)
		(layer "In2.Cu")
		(net "M_A_CPU1_SB_DQ<3>")
	)
	(segment
		(start 69.355716 -230.576374)
		(end 69.355716 -229.845108)
		(width 0.18288)
		(layer "In2.Cu")
		(net "M_A_CPU1_SB_DQ<3>")
	)
	(segment
		(start 83.26628 -238.24438)
		(end 82.759296 -238.24438)
		(width 0.088646)
		(layer "In2.Cu")
		(net "M_A_CPU1_SB_DQ<3>")
	)
	(segment
		(start 69.548756 -230.769414)
		(end 69.355716 -230.576374)
		(width 0.18288)
		(layer "In2.Cu")
		(net "M_A_CPU1_SB_DQ<3>")
	)
	(segment
		(start 68.582794 -229.852474)
		(end 68.582794 -230.50754)
		(width 0.18288)
		(layer "In2.Cu")
		(net "M_A_CPU1_SB_DQ<3>")
	)
	(segment
		(start 67.58813 -229.616762)
		(end 66.152014 -229.616762)
		(width 0.18288)
		(layer "In2.Cu")
		(net "M_A_CPU1_SB_DQ<3>")
	)
	(segment
		(start 82.759296 -238.24438)
		(end 79.108554 -238.24438)
		(width 0.18288)
		(layer "In2.Cu")
		(net "M_A_CPU1_SB_DQ<3>")
	)
	(segment
		(start 88.428068 -237.901226)
		(end 88.427814 -237.901226)
		(width 0.088646)
		(layer "In2.Cu")
		(net "M_A_CPU1_SB_DQ<3>")
	)
	(segment
		(start 90.094816 -238.216694)
		(end 89.842086 -237.963964)
		(width 0.088646)
		(layer "In2.Cu")
		(net "M_A_CPU1_SB_DQ<3>")
	)
	(segment
		(start 69.866002 -230.769414)
		(end 69.548756 -230.769414)
		(width 0.18288)
		(layer "In2.Cu")
		(net "M_A_CPU1_SB_DQ<3>")
	)
	(segment
		(start 68.582794 -230.50754)
		(end 68.389754 -230.70058)
		(width 0.18288)
		(layer "In2.Cu")
		(net "M_A_CPU1_SB_DQ<3>")
	)
	(arc
		(start 90.117168 -238.225838)
		(mid 90.105115 -238.223441)
		(end 90.094816 -238.216694)
		(width 0.088646)
		(layer "In2.Cu")
		(net "M_A_CPU1_SB_DQ<3>")
	)
	(arc
		(start 89.367614 -237.90148)
		(mid 89.084993 -237.977095)
		(end 88.802464 -237.901226)
		(width 0.088646)
		(layer "In2.Cu")
		(net "M_A_CPU1_SB_DQ<3>")
	)
	(arc
		(start 87.488268 -238.549942)
		(mid 87.205566 -238.474166)
		(end 86.922864 -238.549942)
		(width 0.088646)
		(layer "In2.Cu")
		(net "M_A_CPU1_SB_DQ<3>")
	)
	(arc
		(start 89.842086 -237.963964)
		(mid 89.615463 -237.852293)
		(end 89.367614 -237.90148)
		(width 0.088646)
		(layer "In2.Cu")
		(net "M_A_CPU1_SB_DQ<3>")
	)
	(arc
		(start 85.043264 -238.549942)
		(mid 84.856066 -238.600085)
		(end 84.668868 -238.549942)
		(width 0.088646)
		(layer "In2.Cu")
		(net "M_A_CPU1_SB_DQ<3>")
	)
	(arc
		(start 88.427814 -237.901226)
		(mid 88.312701 -238.004529)
		(end 88.249252 -238.145574)
		(width 0.088646)
		(layer "In2.Cu")
		(net "M_A_CPU1_SB_DQ<3>")
	)
	(arc
		(start 87.862664 -238.549942)
		(mid 87.675466 -238.600085)
		(end 87.488268 -238.549942)
		(width 0.088646)
		(layer "In2.Cu")
		(net "M_A_CPU1_SB_DQ<3>")
	)
	(arc
		(start 86.922864 -238.549942)
		(mid 86.735666 -238.600085)
		(end 86.548468 -238.549942)
		(width 0.088646)
		(layer "In2.Cu")
		(net "M_A_CPU1_SB_DQ<3>")
	)
	(arc
		(start 85.983064 -238.549942)
		(mid 85.795866 -238.600085)
		(end 85.608668 -238.549942)
		(width 0.088646)
		(layer "In2.Cu")
		(net "M_A_CPU1_SB_DQ<3>")
	)
	(arc
		(start 86.548468 -238.549942)
		(mid 86.265766 -238.474166)
		(end 85.983064 -238.549942)
		(width 0.088646)
		(layer "In2.Cu")
		(net "M_A_CPU1_SB_DQ<3>")
	)
	(arc
		(start 84.668868 -238.549942)
		(mid 84.386166 -238.474166)
		(end 84.103464 -238.549942)
		(width 0.088646)
		(layer "In2.Cu")
		(net "M_A_CPU1_SB_DQ<3>")
	)
	(arc
		(start 88.802464 -237.901226)
		(mid 88.615266 -237.851083)
		(end 88.428068 -237.901226)
		(width 0.088646)
		(layer "In2.Cu")
		(net "M_A_CPU1_SB_DQ<3>")
	)
	(arc
		(start 85.608668 -238.549942)
		(mid 85.325966 -238.474166)
		(end 85.043264 -238.549942)
		(width 0.088646)
		(layer "In2.Cu")
		(net "M_A_CPU1_SB_DQ<3>")
	)
	(arc
		(start 84.103464 -238.549942)
		(mid 84.013192 -238.587541)
		(end 83.916266 -238.600488)
		(width 0.088646)
		(layer "In2.Cu")
		(net "M_A_CPU1_SB_DQ<3>")
	)
	(arc
		(start 88.018874 -238.374936)
		(mid 87.954819 -238.474977)
		(end 87.862664 -238.549942)
		(width 0.088646)
		(layer "In2.Cu")
		(net "M_A_CPU1_SB_DQ<3>")
	)
	(segment
		(start 85.028278 -218.647772)
		(end 84.753704 -218.373198)
		(width 0.1016)
		(layer "F.Cu")
		(net "M_A_CPU1_SB_DQ<31>")
	)
	(segment
		(start 84.753704 -216.298018)
		(end 85.680296 -215.371426)
		(width 0.1016)
		(layer "F.Cu")
		(net "M_A_CPU1_SB_DQ<31>")
	)
	(segment
		(start 65.089278 -195.574412)
		(end 65.047114 -195.616576)
		(width 0.20066)
		(layer "F.Cu")
		(net "M_A_CPU1_SB_DQ<31>")
	)
	(segment
		(start 59.092338 -195.616322)
		(end 59.530996 -196.05498)
		(width 0.20066)
		(layer "F.Cu")
		(net "M_A_CPU1_SB_DQ<31>")
	)
	(segment
		(start 59.822842 -196.05498)
		(end 59.836304 -196.041518)
		(width 0.101854)
		(layer "F.Cu")
		(net "M_A_CPU1_SB_DQ<31>")
	)
	(segment
		(start 62.147958 -196.041518)
		(end 62.59195 -196.041518)
		(width 0.20066)
		(layer "F.Cu")
		(net "M_A_CPU1_SB_DQ<31>")
	)
	(segment
		(start 62.59195 -196.041518)
		(end 62.681612 -195.951856)
		(width 0.20066)
		(layer "F.Cu")
		(net "M_A_CPU1_SB_DQ<31>")
	)
	(segment
		(start 86.367874 -219.129864)
		(end 85.838538 -218.824048)
		(width 0.088646)
		(layer "F.Cu")
		(net "M_A_CPU1_SB_DQ<31>")
	)
	(segment
		(start 57.503314 -195.616576)
		(end 57.503568 -195.616322)
		(width 0.20066)
		(layer "F.Cu")
		(net "M_A_CPU1_SB_DQ<31>")
	)
	(segment
		(start 85.702648 -218.787472)
		(end 85.167978 -218.787472)
		(width 0.088646)
		(layer "F.Cu")
		(net "M_A_CPU1_SB_DQ<31>")
	)
	(segment
		(start 86.120224 -215.371426)
		(end 87.287354 -214.204296)
		(width 0.1016)
		(layer "F.Cu")
		(net "M_A_CPU1_SB_DQ<31>")
	)
	(segment
		(start 61.87567 -196.041518)
		(end 62.147958 -196.041518)
		(width 0.101854)
		(layer "F.Cu")
		(net "M_A_CPU1_SB_DQ<31>")
	)
	(segment
		(start 62.808612 -195.43395)
		(end 63.97371 -195.43395)
		(width 0.20066)
		(layer "F.Cu")
		(net "M_A_CPU1_SB_DQ<31>")
	)
	(segment
		(start 59.530996 -196.05498)
		(end 59.822842 -196.05498)
		(width 0.20066)
		(layer "F.Cu")
		(net "M_A_CPU1_SB_DQ<31>")
	)
	(segment
		(start 84.753704 -218.373198)
		(end 84.753704 -216.298018)
		(width 0.1016)
		(layer "F.Cu")
		(net "M_A_CPU1_SB_DQ<31>")
	)
	(segment
		(start 76.1238 -197.228206)
		(end 72.889618 -195.88861)
		(width 0.20066)
		(layer "F.Cu")
		(net "M_A_CPU1_SB_DQ<31>")
	)
	(segment
		(start 87.287354 -209.34553)
		(end 86.612984 -207.71739)
		(width 0.20066)
		(layer "F.Cu")
		(net "M_A_CPU1_SB_DQ<31>")
	)
	(segment
		(start 59.836304 -196.041518)
		(end 60.088018 -196.041518)
		(width 0.101854)
		(layer "F.Cu")
		(net "M_A_CPU1_SB_DQ<31>")
	)
	(segment
		(start 85.167978 -218.787472)
		(end 85.028278 -218.647772)
		(width 0.088646)
		(layer "F.Cu")
		(net "M_A_CPU1_SB_DQ<31>")
	)
	(segment
		(start 87.287354 -214.033608)
		(end 87.287354 -209.34553)
		(width 0.20066)
		(layer "F.Cu")
		(net "M_A_CPU1_SB_DQ<31>")
	)
	(segment
		(start 86.735666 -219.228162)
		(end 86.367874 -219.129864)
		(width 0.088646)
		(layer "F.Cu")
		(net "M_A_CPU1_SB_DQ<31>")
	)
	(segment
		(start 62.681612 -195.951856)
		(end 62.681612 -195.56095)
		(width 0.20066)
		(layer "F.Cu")
		(net "M_A_CPU1_SB_DQ<31>")
	)
	(segment
		(start 64.156336 -195.616576)
		(end 65.047114 -195.616576)
		(width 0.20066)
		(layer "F.Cu")
		(net "M_A_CPU1_SB_DQ<31>")
	)
	(segment
		(start 62.681612 -195.56095)
		(end 62.808612 -195.43395)
		(width 0.20066)
		(layer "F.Cu")
		(net "M_A_CPU1_SB_DQ<31>")
	)
	(segment
		(start 57.503568 -195.616322)
		(end 59.092338 -195.616322)
		(width 0.20066)
		(layer "F.Cu")
		(net "M_A_CPU1_SB_DQ<31>")
	)
	(segment
		(start 85.680296 -215.371426)
		(end 86.120224 -215.371426)
		(width 0.1016)
		(layer "F.Cu")
		(net "M_A_CPU1_SB_DQ<31>")
	)
	(segment
		(start 67.332098 -195.574412)
		(end 65.089278 -195.574412)
		(width 0.20066)
		(layer "F.Cu")
		(net "M_A_CPU1_SB_DQ<31>")
	)
	(segment
		(start 87.287354 -214.204296)
		(end 87.287354 -214.033608)
		(width 0.1016)
		(layer "F.Cu")
		(net "M_A_CPU1_SB_DQ<31>")
	)
	(segment
		(start 63.97371 -195.43395)
		(end 64.156336 -195.616576)
		(width 0.20066)
		(layer "F.Cu")
		(net "M_A_CPU1_SB_DQ<31>")
	)
	(segment
		(start 72.889618 -195.88861)
		(end 67.646296 -195.88861)
		(width 0.20066)
		(layer "F.Cu")
		(net "M_A_CPU1_SB_DQ<31>")
	)
	(segment
		(start 67.646296 -195.88861)
		(end 67.332098 -195.574412)
		(width 0.20066)
		(layer "F.Cu")
		(net "M_A_CPU1_SB_DQ<31>")
	)
	(segment
		(start 86.612984 -207.71739)
		(end 76.1238 -197.228206)
		(width 0.20066)
		(layer "F.Cu")
		(net "M_A_CPU1_SB_DQ<31>")
	)
	(segment
		(start 60.088018 -196.041518)
		(end 61.87567 -196.041518)
		(width 0.1016)
		(layer "F.Cu")
		(net "M_A_CPU1_SB_DQ<31>")
	)
	(arc
		(start 85.838538 -218.824048)
		(mid 85.773 -218.796819)
		(end 85.702648 -218.787472)
		(width 0.088646)
		(layer "F.Cu")
		(net "M_A_CPU1_SB_DQ<31>")
	)
	(segment
		(start 62.808612 -197.133972)
		(end 63.979298 -197.133972)
		(width 0.20066)
		(layer "F.Cu")
		(net "M_A_CPU1_SB_DQ<30>")
	)
	(segment
		(start 59.85637 -197.761098)
		(end 59.874658 -197.74281)
		(width 0.101854)
		(layer "F.Cu")
		(net "M_A_CPU1_SB_DQ<30>")
	)
	(segment
		(start 84.619084 -219.10421)
		(end 84.595462 -219.080588)
		(width 0.088646)
		(layer "F.Cu")
		(net "M_A_CPU1_SB_DQ<30>")
	)
	(segment
		(start 61.875416 -197.74154)
		(end 61.881766 -197.74789)
		(width 0.1016)
		(layer "F.Cu")
		(net "M_A_CPU1_SB_DQ<30>")
	)
	(segment
		(start 84.621116 -219.10421)
		(end 84.619084 -219.10421)
		(width 0.088646)
		(layer "F.Cu")
		(net "M_A_CPU1_SB_DQ<30>")
	)
	(segment
		(start 87.49284 -219.726764)
		(end 87.361522 -219.595446)
		(width 0.088646)
		(layer "F.Cu")
		(net "M_A_CPU1_SB_DQ<30>")
	)
	(segment
		(start 87.205312 -220.041978)
		(end 87.425784 -220.040962)
		(width 0.088646)
		(layer "F.Cu")
		(net "M_A_CPU1_SB_DQ<30>")
	)
	(segment
		(start 86.007194 -214.18042)
		(end 86.007194 -214.033608)
		(width 0.1016)
		(layer "F.Cu")
		(net "M_A_CPU1_SB_DQ<30>")
	)
	(segment
		(start 75.399392 -198.312786)
		(end 72.728582 -197.206616)
		(width 0.20066)
		(layer "F.Cu")
		(net "M_A_CPU1_SB_DQ<30>")
	)
	(segment
		(start 59.874658 -197.74281)
		(end 60.084208 -197.74281)
		(width 0.101854)
		(layer "F.Cu")
		(net "M_A_CPU1_SB_DQ<30>")
	)
	(segment
		(start 87.425784 -220.040962)
		(end 87.494618 -219.971366)
		(width 0.088646)
		(layer "F.Cu")
		(net "M_A_CPU1_SB_DQ<30>")
	)
	(segment
		(start 65.157096 -197.206616)
		(end 65.047114 -197.316598)
		(width 0.20066)
		(layer "F.Cu")
		(net "M_A_CPU1_SB_DQ<30>")
	)
	(segment
		(start 85.527642 -208.441036)
		(end 75.399392 -198.312786)
		(width 0.20066)
		(layer "F.Cu")
		(net "M_A_CPU1_SB_DQ<30>")
	)
	(segment
		(start 62.681612 -197.260972)
		(end 62.808612 -197.133972)
		(width 0.20066)
		(layer "F.Cu")
		(net "M_A_CPU1_SB_DQ<30>")
	)
	(segment
		(start 85.205316 -219.41663)
		(end 84.933536 -219.41663)
		(width 0.088646)
		(layer "F.Cu")
		(net "M_A_CPU1_SB_DQ<30>")
	)
	(segment
		(start 59.822842 -197.761098)
		(end 59.85637 -197.761098)
		(width 0.101854)
		(layer "F.Cu")
		(net "M_A_CPU1_SB_DQ<30>")
	)
	(segment
		(start 85.384132 -219.595446)
		(end 85.205316 -219.41663)
		(width 0.088646)
		(layer "F.Cu")
		(net "M_A_CPU1_SB_DQ<30>")
	)
	(segment
		(start 86.007194 -209.598768)
		(end 85.527642 -208.441036)
		(width 0.20066)
		(layer "F.Cu")
		(net "M_A_CPU1_SB_DQ<30>")
	)
	(segment
		(start 63.979298 -197.133972)
		(end 64.161924 -197.316598)
		(width 0.20066)
		(layer "F.Cu")
		(net "M_A_CPU1_SB_DQ<30>")
	)
	(segment
		(start 87.361522 -219.595446)
		(end 85.384132 -219.595446)
		(width 0.088646)
		(layer "F.Cu")
		(net "M_A_CPU1_SB_DQ<30>")
	)
	(segment
		(start 87.494618 -219.971366)
		(end 87.49284 -219.726764)
		(width 0.088646)
		(layer "F.Cu")
		(net "M_A_CPU1_SB_DQ<30>")
	)
	(segment
		(start 59.537092 -197.761098)
		(end 59.822842 -197.761098)
		(width 0.20066)
		(layer "F.Cu")
		(net "M_A_CPU1_SB_DQ<30>")
	)
	(segment
		(start 84.933536 -219.41663)
		(end 84.621116 -219.10421)
		(width 0.088646)
		(layer "F.Cu")
		(net "M_A_CPU1_SB_DQ<30>")
	)
	(segment
		(start 60.084208 -197.74281)
		(end 60.088018 -197.74154)
		(width 0.1016)
		(layer "F.Cu")
		(net "M_A_CPU1_SB_DQ<30>")
	)
	(segment
		(start 62.681612 -197.651878)
		(end 62.681612 -197.260972)
		(width 0.20066)
		(layer "F.Cu")
		(net "M_A_CPU1_SB_DQ<30>")
	)
	(segment
		(start 72.728582 -197.206616)
		(end 65.157096 -197.206616)
		(width 0.20066)
		(layer "F.Cu")
		(net "M_A_CPU1_SB_DQ<30>")
	)
	(segment
		(start 62.147958 -197.74789)
		(end 62.5856 -197.74789)
		(width 0.20066)
		(layer "F.Cu")
		(net "M_A_CPU1_SB_DQ<30>")
	)
	(segment
		(start 84.595462 -219.080588)
		(end 84.144104 -218.62923)
		(width 0.1016)
		(layer "F.Cu")
		(net "M_A_CPU1_SB_DQ<30>")
	)
	(segment
		(start 57.503314 -197.316598)
		(end 59.092592 -197.316598)
		(width 0.20066)
		(layer "F.Cu")
		(net "M_A_CPU1_SB_DQ<30>")
	)
	(segment
		(start 62.5856 -197.74789)
		(end 62.681612 -197.651878)
		(width 0.20066)
		(layer "F.Cu")
		(net "M_A_CPU1_SB_DQ<30>")
	)
	(segment
		(start 59.092592 -197.316598)
		(end 59.537092 -197.761098)
		(width 0.20066)
		(layer "F.Cu")
		(net "M_A_CPU1_SB_DQ<30>")
	)
	(segment
		(start 86.007194 -214.033608)
		(end 86.007194 -209.598768)
		(width 0.20066)
		(layer "F.Cu")
		(net "M_A_CPU1_SB_DQ<30>")
	)
	(segment
		(start 84.144104 -218.62923)
		(end 84.144104 -216.04351)
		(width 0.1016)
		(layer "F.Cu")
		(net "M_A_CPU1_SB_DQ<30>")
	)
	(segment
		(start 60.088018 -197.74154)
		(end 61.875416 -197.74154)
		(width 0.1016)
		(layer "F.Cu")
		(net "M_A_CPU1_SB_DQ<30>")
	)
	(segment
		(start 64.161924 -197.316598)
		(end 65.047114 -197.316598)
		(width 0.20066)
		(layer "F.Cu")
		(net "M_A_CPU1_SB_DQ<30>")
	)
	(segment
		(start 61.881766 -197.74789)
		(end 62.147958 -197.74789)
		(width 0.101854)
		(layer "F.Cu")
		(net "M_A_CPU1_SB_DQ<30>")
	)
	(segment
		(start 84.144104 -216.04351)
		(end 86.007194 -214.18042)
		(width 0.1016)
		(layer "F.Cu")
		(net "M_A_CPU1_SB_DQ<30>")
	)
	(segment
		(start 59.822842 -231.750616)
		(end 59.600084 -231.750616)
		(width 0.20066)
		(layer "F.Cu")
		(net "M_A_CPU1_SB_DQ<2>")
	)
	(segment
		(start 63.329312 -231.095042)
		(end 62.83579 -231.095042)
		(width 0.20066)
		(layer "F.Cu")
		(net "M_A_CPU1_SB_DQ<2>")
	)
	(segment
		(start 63.551054 -231.316784)
		(end 63.329312 -231.095042)
		(width 0.20066)
		(layer "F.Cu")
		(net "M_A_CPU1_SB_DQ<2>")
	)
	(segment
		(start 59.600084 -231.750616)
		(end 59.166252 -231.316784)
		(width 0.20066)
		(layer "F.Cu")
		(net "M_A_CPU1_SB_DQ<2>")
	)
	(segment
		(start 62.669928 -231.260904)
		(end 62.669928 -231.614472)
		(width 0.20066)
		(layer "F.Cu")
		(net "M_A_CPU1_SB_DQ<2>")
	)
	(segment
		(start 59.855608 -231.750616)
		(end 59.822842 -231.750616)
		(width 0.101854)
		(layer "F.Cu")
		(net "M_A_CPU1_SB_DQ<2>")
	)
	(segment
		(start 62.669928 -231.614472)
		(end 62.542674 -231.741726)
		(width 0.20066)
		(layer "F.Cu")
		(net "M_A_CPU1_SB_DQ<2>")
	)
	(segment
		(start 62.147958 -231.741726)
		(end 62.046612 -231.741726)
		(width 0.101854)
		(layer "F.Cu")
		(net "M_A_CPU1_SB_DQ<2>")
	)
	(segment
		(start 62.83579 -231.095042)
		(end 62.669928 -231.260904)
		(width 0.20066)
		(layer "F.Cu")
		(net "M_A_CPU1_SB_DQ<2>")
	)
	(segment
		(start 59.887612 -231.741726)
		(end 59.864498 -231.741726)
		(width 0.101854)
		(layer "F.Cu")
		(net "M_A_CPU1_SB_DQ<2>")
	)
	(segment
		(start 90.024712 -239.57534)
		(end 90.024966 -239.0394)
		(width 0.20066)
		(layer "F.Cu")
		(net "M_A_CPU1_SB_DQ<2>")
	)
	(segment
		(start 59.166252 -231.316784)
		(end 57.503314 -231.316784)
		(width 0.20066)
		(layer "F.Cu")
		(net "M_A_CPU1_SB_DQ<2>")
	)
	(segment
		(start 59.864498 -231.741726)
		(end 59.855608 -231.750616)
		(width 0.101854)
		(layer "F.Cu")
		(net "M_A_CPU1_SB_DQ<2>")
	)
	(segment
		(start 65.047114 -231.316784)
		(end 63.551054 -231.316784)
		(width 0.20066)
		(layer "F.Cu")
		(net "M_A_CPU1_SB_DQ<2>")
	)
	(segment
		(start 62.542674 -231.741726)
		(end 62.147958 -231.741726)
		(width 0.20066)
		(layer "F.Cu")
		(net "M_A_CPU1_SB_DQ<2>")
	)
	(segment
		(start 62.046612 -231.741726)
		(end 59.887612 -231.741726)
		(width 0.1016)
		(layer "F.Cu")
		(net "M_A_CPU1_SB_DQ<2>")
	)
	(segment
		(start 66.152014 -231.316784)
		(end 65.047114 -231.316784)
		(width 0.20066)
		(layer "F.Cu")
		(net "M_A_CPU1_SB_DQ<2>")
	)
	(segment
		(start 86.467696 -239.355122)
		(end 86.452964 -239.363758)
		(width 0.088646)
		(layer "In2.Cu")
		(net "M_A_CPU1_SB_DQ<2>")
	)
	(segment
		(start 74.961496 -236.062012)
		(end 74.6887 -236.062012)
		(width 0.18288)
		(layer "In2.Cu")
		(net "M_A_CPU1_SB_DQ<2>")
	)
	(segment
		(start 73.460102 -234.840018)
		(end 73.460102 -234.567222)
		(width 0.18288)
		(layer "In2.Cu")
		(net "M_A_CPU1_SB_DQ<2>")
	)
	(segment
		(start 75.569572 -236.452664)
		(end 75.569572 -236.179868)
		(width 0.18288)
		(layer "In2.Cu")
		(net "M_A_CPU1_SB_DQ<2>")
	)
	(segment
		(start 76.5683 -237.178596)
		(end 76.341732 -236.952028)
		(width 0.18288)
		(layer "In2.Cu")
		(net "M_A_CPU1_SB_DQ<2>")
	)
	(segment
		(start 72.573388 -233.45648)
		(end 72.573388 -233.183684)
		(width 0.18288)
		(layer "In2.Cu")
		(net "M_A_CPU1_SB_DQ<2>")
	)
	(segment
		(start 88.341454 -239.358678)
		(end 88.332564 -239.363758)
		(width 0.088646)
		(layer "In2.Cu")
		(net "M_A_CPU1_SB_DQ<2>")
	)
	(segment
		(start 71.715376 -233.042968)
		(end 71.488808 -232.8164)
		(width 0.18288)
		(layer "In2.Cu")
		(net "M_A_CPU1_SB_DQ<2>")
	)
	(segment
		(start 72.463152 -233.839512)
		(end 72.463152 -233.566716)
		(width 0.18288)
		(layer "In2.Cu")
		(net "M_A_CPU1_SB_DQ<2>")
	)
	(segment
		(start 88.520016 -239.023906)
		(end 88.520016 -239.0394)
		(width 0.088646)
		(layer "In2.Cu")
		(net "M_A_CPU1_SB_DQ<2>")
	)
	(segment
		(start 72.34682 -232.957116)
		(end 72.074024 -232.957116)
		(width 0.18288)
		(layer "In2.Cu")
		(net "M_A_CPU1_SB_DQ<2>")
	)
	(segment
		(start 75.46086 -236.561376)
		(end 75.569572 -236.452664)
		(width 0.18288)
		(layer "In2.Cu")
		(net "M_A_CPU1_SB_DQ<2>")
	)
	(segment
		(start 75.070208 -235.9533)
		(end 74.961496 -236.062012)
		(width 0.18288)
		(layer "In2.Cu")
		(net "M_A_CPU1_SB_DQ<2>")
	)
	(segment
		(start 66.360548 -231.10825)
		(end 66.152014 -231.316784)
		(width 0.18288)
		(layer "In2.Cu")
		(net "M_A_CPU1_SB_DQ<2>")
	)
	(segment
		(start 71.217028 -231.827324)
		(end 67.986402 -231.827324)
		(width 0.18288)
		(layer "In2.Cu")
		(net "M_A_CPU1_SB_DQ<2>")
	)
	(segment
		(start 76.454508 -237.83798)
		(end 76.454508 -237.565184)
		(width 0.18288)
		(layer "In2.Cu")
		(net "M_A_CPU1_SB_DQ<2>")
	)
	(segment
		(start 75.343004 -235.9533)
		(end 75.070208 -235.9533)
		(width 0.18288)
		(layer "In2.Cu")
		(net "M_A_CPU1_SB_DQ<2>")
	)
	(segment
		(start 75.46086 -236.834172)
		(end 75.46086 -236.561376)
		(width 0.18288)
		(layer "In2.Cu")
		(net "M_A_CPU1_SB_DQ<2>")
	)
	(segment
		(start 72.68972 -234.06608)
		(end 72.463152 -233.839512)
		(width 0.18288)
		(layer "In2.Cu")
		(net "M_A_CPU1_SB_DQ<2>")
	)
	(segment
		(start 75.960224 -237.06074)
		(end 75.687428 -237.06074)
		(width 0.18288)
		(layer "In2.Cu")
		(net "M_A_CPU1_SB_DQ<2>")
	)
	(segment
		(start 87.407496 -239.355122)
		(end 87.392764 -239.363758)
		(width 0.088646)
		(layer "In2.Cu")
		(net "M_A_CPU1_SB_DQ<2>")
	)
	(segment
		(start 85.527896 -239.355122)
		(end 85.513164 -239.363758)
		(width 0.088646)
		(layer "In2.Cu")
		(net "M_A_CPU1_SB_DQ<2>")
	)
	(segment
		(start 72.573388 -233.183684)
		(end 72.34682 -232.957116)
		(width 0.18288)
		(layer "In2.Cu")
		(net "M_A_CPU1_SB_DQ<2>")
	)
	(segment
		(start 74.570844 -235.453936)
		(end 74.570844 -235.18114)
		(width 0.18288)
		(layer "In2.Cu")
		(net "M_A_CPU1_SB_DQ<2>")
	)
	(segment
		(start 76.5683 -237.451392)
		(end 76.5683 -237.178596)
		(width 0.18288)
		(layer "In2.Cu")
		(net "M_A_CPU1_SB_DQ<2>")
	)
	(segment
		(start 89.367614 -238.549942)
		(end 89.352882 -238.541306)
		(width 0.088646)
		(layer "In2.Cu")
		(net "M_A_CPU1_SB_DQ<2>")
	)
	(segment
		(start 73.572116 -234.182412)
		(end 73.345548 -233.955844)
		(width 0.18288)
		(layer "In2.Cu")
		(net "M_A_CPU1_SB_DQ<2>")
	)
	(segment
		(start 71.488808 -232.8164)
		(end 71.488808 -232.543604)
		(width 0.18288)
		(layer "In2.Cu")
		(net "M_A_CPU1_SB_DQ<2>")
	)
	(segment
		(start 74.462132 -235.562648)
		(end 74.570844 -235.453936)
		(width 0.18288)
		(layer "In2.Cu")
		(net "M_A_CPU1_SB_DQ<2>")
	)
	(segment
		(start 76.068936 -236.952028)
		(end 75.960224 -237.06074)
		(width 0.18288)
		(layer "In2.Cu")
		(net "M_A_CPU1_SB_DQ<2>")
	)
	(segment
		(start 71.57466 -232.184956)
		(end 71.217028 -231.827324)
		(width 0.18288)
		(layer "In2.Cu")
		(net "M_A_CPU1_SB_DQ<2>")
	)
	(segment
		(start 71.57466 -232.457752)
		(end 71.57466 -232.184956)
		(width 0.18288)
		(layer "In2.Cu")
		(net "M_A_CPU1_SB_DQ<2>")
	)
	(segment
		(start 76.454508 -237.565184)
		(end 76.5683 -237.451392)
		(width 0.18288)
		(layer "In2.Cu")
		(net "M_A_CPU1_SB_DQ<2>")
	)
	(segment
		(start 84.386166 -239.414304)
		(end 83.61172 -239.414304)
		(width 0.088646)
		(layer "In2.Cu")
		(net "M_A_CPU1_SB_DQ<2>")
	)
	(segment
		(start 74.462132 -235.835444)
		(end 74.462132 -235.562648)
		(width 0.18288)
		(layer "In2.Cu")
		(net "M_A_CPU1_SB_DQ<2>")
	)
	(segment
		(start 73.345548 -233.955844)
		(end 73.072752 -233.955844)
		(width 0.18288)
		(layer "In2.Cu")
		(net "M_A_CPU1_SB_DQ<2>")
	)
	(segment
		(start 77.067664 -237.950756)
		(end 76.953872 -238.064548)
		(width 0.18288)
		(layer "In2.Cu")
		(net "M_A_CPU1_SB_DQ<2>")
	)
	(segment
		(start 73.959466 -235.066586)
		(end 73.68667 -235.066586)
		(width 0.18288)
		(layer "In2.Cu")
		(net "M_A_CPU1_SB_DQ<2>")
	)
	(segment
		(start 78.324964 -238.93526)
		(end 77.34046 -237.950756)
		(width 0.18288)
		(layer "In2.Cu")
		(net "M_A_CPU1_SB_DQ<2>")
	)
	(segment
		(start 66.71056 -231.10825)
		(end 66.360548 -231.10825)
		(width 0.18288)
		(layer "In2.Cu")
		(net "M_A_CPU1_SB_DQ<2>")
	)
	(segment
		(start 89.712038 -239.0394)
		(end 89.646506 -238.973868)
		(width 0.088646)
		(layer "In2.Cu")
		(net "M_A_CPU1_SB_DQ<2>")
	)
	(segment
		(start 83.132676 -238.93526)
		(end 82.759296 -238.93526)
		(width 0.088646)
		(layer "In2.Cu")
		(net "M_A_CPU1_SB_DQ<2>")
	)
	(segment
		(start 90.024966 -239.0394)
		(end 89.712038 -239.0394)
		(width 0.088646)
		(layer "In2.Cu")
		(net "M_A_CPU1_SB_DQ<2>")
	)
	(segment
		(start 71.488808 -232.543604)
		(end 71.57466 -232.457752)
		(width 0.18288)
		(layer "In2.Cu")
		(net "M_A_CPU1_SB_DQ<2>")
	)
	(segment
		(start 73.572116 -234.455208)
		(end 73.572116 -234.182412)
		(width 0.18288)
		(layer "In2.Cu")
		(net "M_A_CPU1_SB_DQ<2>")
	)
	(segment
		(start 75.687428 -237.06074)
		(end 75.46086 -236.834172)
		(width 0.18288)
		(layer "In2.Cu")
		(net "M_A_CPU1_SB_DQ<2>")
	)
	(segment
		(start 89.37371 -238.553498)
		(end 89.367614 -238.549942)
		(width 0.088646)
		(layer "In2.Cu")
		(net "M_A_CPU1_SB_DQ<2>")
	)
	(segment
		(start 83.61172 -239.414304)
		(end 83.132676 -238.93526)
		(width 0.088646)
		(layer "In2.Cu")
		(net "M_A_CPU1_SB_DQ<2>")
	)
	(segment
		(start 72.074024 -232.957116)
		(end 71.988172 -233.042968)
		(width 0.18288)
		(layer "In2.Cu")
		(net "M_A_CPU1_SB_DQ<2>")
	)
	(segment
		(start 71.988172 -233.042968)
		(end 71.715376 -233.042968)
		(width 0.18288)
		(layer "In2.Cu")
		(net "M_A_CPU1_SB_DQ<2>")
	)
	(segment
		(start 82.759296 -238.93526)
		(end 78.324964 -238.93526)
		(width 0.18288)
		(layer "In2.Cu")
		(net "M_A_CPU1_SB_DQ<2>")
	)
	(segment
		(start 75.569572 -236.179868)
		(end 75.343004 -235.9533)
		(width 0.18288)
		(layer "In2.Cu")
		(net "M_A_CPU1_SB_DQ<2>")
	)
	(segment
		(start 73.072752 -233.955844)
		(end 72.962516 -234.06608)
		(width 0.18288)
		(layer "In2.Cu")
		(net "M_A_CPU1_SB_DQ<2>")
	)
	(segment
		(start 72.463152 -233.566716)
		(end 72.573388 -233.45648)
		(width 0.18288)
		(layer "In2.Cu")
		(net "M_A_CPU1_SB_DQ<2>")
	)
	(segment
		(start 67.986402 -231.827324)
		(end 67.036188 -231.433878)
		(width 0.18288)
		(layer "In2.Cu")
		(net "M_A_CPU1_SB_DQ<2>")
	)
	(segment
		(start 73.460102 -234.567222)
		(end 73.572116 -234.455208)
		(width 0.18288)
		(layer "In2.Cu")
		(net "M_A_CPU1_SB_DQ<2>")
	)
	(segment
		(start 73.68667 -235.066586)
		(end 73.460102 -234.840018)
		(width 0.18288)
		(layer "In2.Cu")
		(net "M_A_CPU1_SB_DQ<2>")
	)
	(segment
		(start 76.681076 -238.064548)
		(end 76.454508 -237.83798)
		(width 0.18288)
		(layer "In2.Cu")
		(net "M_A_CPU1_SB_DQ<2>")
	)
	(segment
		(start 77.34046 -237.950756)
		(end 77.067664 -237.950756)
		(width 0.18288)
		(layer "In2.Cu")
		(net "M_A_CPU1_SB_DQ<2>")
	)
	(segment
		(start 76.953872 -238.064548)
		(end 76.681076 -238.064548)
		(width 0.18288)
		(layer "In2.Cu")
		(net "M_A_CPU1_SB_DQ<2>")
	)
	(segment
		(start 67.036188 -231.433878)
		(end 66.71056 -231.10825)
		(width 0.18288)
		(layer "In2.Cu")
		(net "M_A_CPU1_SB_DQ<2>")
	)
	(segment
		(start 74.570844 -235.18114)
		(end 74.344276 -234.954572)
		(width 0.18288)
		(layer "In2.Cu")
		(net "M_A_CPU1_SB_DQ<2>")
	)
	(segment
		(start 72.962516 -234.06608)
		(end 72.68972 -234.06608)
		(width 0.18288)
		(layer "In2.Cu")
		(net "M_A_CPU1_SB_DQ<2>")
	)
	(segment
		(start 74.344276 -234.954572)
		(end 74.07148 -234.954572)
		(width 0.18288)
		(layer "In2.Cu")
		(net "M_A_CPU1_SB_DQ<2>")
	)
	(segment
		(start 76.341732 -236.952028)
		(end 76.068936 -236.952028)
		(width 0.18288)
		(layer "In2.Cu")
		(net "M_A_CPU1_SB_DQ<2>")
	)
	(segment
		(start 74.07148 -234.954572)
		(end 73.959466 -235.066586)
		(width 0.18288)
		(layer "In2.Cu")
		(net "M_A_CPU1_SB_DQ<2>")
	)
	(segment
		(start 74.6887 -236.062012)
		(end 74.462132 -235.835444)
		(width 0.18288)
		(layer "In2.Cu")
		(net "M_A_CPU1_SB_DQ<2>")
	)
	(arc
		(start 87.018368 -239.363758)
		(mid 86.744169 -239.287923)
		(end 86.467696 -239.355122)
		(width 0.088646)
		(layer "In2.Cu")
		(net "M_A_CPU1_SB_DQ<2>")
	)
	(arc
		(start 88.520016 -239.0394)
		(mid 88.472337 -239.2223)
		(end 88.341454 -239.358678)
		(width 0.088646)
		(layer "In2.Cu")
		(net "M_A_CPU1_SB_DQ<2>")
	)
	(arc
		(start 85.513164 -239.363758)
		(mid 85.325966 -239.413901)
		(end 85.138768 -239.363758)
		(width 0.088646)
		(layer "In2.Cu")
		(net "M_A_CPU1_SB_DQ<2>")
	)
	(arc
		(start 87.392764 -239.363758)
		(mid 87.205566 -239.413901)
		(end 87.018368 -239.363758)
		(width 0.088646)
		(layer "In2.Cu")
		(net "M_A_CPU1_SB_DQ<2>")
	)
	(arc
		(start 88.80221 -238.549942)
		(mid 88.599387 -238.750173)
		(end 88.520016 -239.023906)
		(width 0.088646)
		(layer "In2.Cu")
		(net "M_A_CPU1_SB_DQ<2>")
	)
	(arc
		(start 89.352882 -238.541306)
		(mid 89.076407 -238.473986)
		(end 88.80221 -238.549942)
		(width 0.088646)
		(layer "In2.Cu")
		(net "M_A_CPU1_SB_DQ<2>")
	)
	(arc
		(start 89.646506 -238.973868)
		(mid 89.559262 -238.73178)
		(end 89.37371 -238.553498)
		(width 0.088646)
		(layer "In2.Cu")
		(net "M_A_CPU1_SB_DQ<2>")
	)
	(arc
		(start 88.332564 -239.363758)
		(mid 88.145366 -239.413901)
		(end 87.958168 -239.363758)
		(width 0.088646)
		(layer "In2.Cu")
		(net "M_A_CPU1_SB_DQ<2>")
	)
	(arc
		(start 85.138768 -239.363758)
		(mid 84.864569 -239.287923)
		(end 84.588096 -239.355122)
		(width 0.088646)
		(layer "In2.Cu")
		(net "M_A_CPU1_SB_DQ<2>")
	)
	(arc
		(start 87.958168 -239.363758)
		(mid 87.683969 -239.287923)
		(end 87.407496 -239.355122)
		(width 0.088646)
		(layer "In2.Cu")
		(net "M_A_CPU1_SB_DQ<2>")
	)
	(arc
		(start 84.588096 -239.355122)
		(mid 84.491369 -239.399174)
		(end 84.386166 -239.414304)
		(width 0.088646)
		(layer "In2.Cu")
		(net "M_A_CPU1_SB_DQ<2>")
	)
	(arc
		(start 86.452964 -239.363758)
		(mid 86.265766 -239.413901)
		(end 86.078568 -239.363758)
		(width 0.088646)
		(layer "In2.Cu")
		(net "M_A_CPU1_SB_DQ<2>")
	)
	(arc
		(start 86.078568 -239.363758)
		(mid 85.804369 -239.287923)
		(end 85.527896 -239.355122)
		(width 0.088646)
		(layer "In2.Cu")
		(net "M_A_CPU1_SB_DQ<2>")
	)
	(segment
		(start 75.761596 -197.770496)
		(end 72.824848 -196.55409)
		(width 0.20066)
		(layer "F.Cu")
		(net "M_A_CPU1_SB_DQ<29>")
	)
	(segment
		(start 84.981796 -219.032582)
		(end 84.812632 -218.863418)
		(width 0.088646)
		(layer "F.Cu")
		(net "M_A_CPU1_SB_DQ<29>")
	)
	(segment
		(start 58.704226 -196.041518)
		(end 58.858912 -196.041518)
		(width 0.20066)
		(layer "F.Cu")
		(net "M_A_CPU1_SB_DQ<29>")
	)
	(segment
		(start 56.413146 -196.041518)
		(end 58.349134 -196.041518)
		(width 0.1016)
		(layer "F.Cu")
		(net "M_A_CPU1_SB_DQ<29>")
	)
	(segment
		(start 63.932562 -196.041518)
		(end 63.926212 -196.035168)
		(width 0.1016)
		(layer "F.Cu")
		(net "M_A_CPU1_SB_DQ<29>")
	)
	(segment
		(start 86.647274 -214.033608)
		(end 86.647274 -209.472022)
		(width 0.20066)
		(layer "F.Cu")
		(net "M_A_CPU1_SB_DQ<29>")
	)
	(segment
		(start 55.583328 -196.490336)
		(end 55.583328 -196.196204)
		(width 0.20066)
		(layer "F.Cu")
		(net "M_A_CPU1_SB_DQ<29>")
	)
	(segment
		(start 55.583328 -196.196204)
		(end 55.748428 -196.031104)
		(width 0.20066)
		(layer "F.Cu")
		(net "M_A_CPU1_SB_DQ<29>")
	)
	(segment
		(start 72.824848 -196.55409)
		(end 66.976244 -196.55409)
		(width 0.20066)
		(layer "F.Cu")
		(net "M_A_CPU1_SB_DQ<29>")
	)
	(segment
		(start 84.812632 -218.863418)
		(end 84.448904 -218.49969)
		(width 0.1016)
		(layer "F.Cu")
		(net "M_A_CPU1_SB_DQ<29>")
	)
	(segment
		(start 66.237612 -196.041518)
		(end 63.932562 -196.041518)
		(width 0.1016)
		(layer "F.Cu")
		(net "M_A_CPU1_SB_DQ<29>")
	)
	(segment
		(start 54.965092 -196.718428)
		(end 55.355236 -196.718428)
		(width 0.20066)
		(layer "F.Cu")
		(net "M_A_CPU1_SB_DQ<29>")
	)
	(segment
		(start 55.748428 -196.031104)
		(end 56.37911 -196.031104)
		(width 0.20066)
		(layer "F.Cu")
		(net "M_A_CPU1_SB_DQ<29>")
	)
	(segment
		(start 58.349134 -196.041518)
		(end 58.704226 -196.041518)
		(width 0.101854)
		(layer "F.Cu")
		(net "M_A_CPU1_SB_DQ<29>")
	)
	(segment
		(start 56.37911 -196.031104)
		(end 56.413146 -196.041518)
		(width 0.1016)
		(layer "F.Cu")
		(net "M_A_CPU1_SB_DQ<29>")
	)
	(segment
		(start 63.181738 -196.466714)
		(end 60.947046 -196.466714)
		(width 0.20066)
		(layer "F.Cu")
		(net "M_A_CPU1_SB_DQ<29>")
	)
	(segment
		(start 54.713378 -196.466714)
		(end 54.965092 -196.718428)
		(width 0.20066)
		(layer "F.Cu")
		(net "M_A_CPU1_SB_DQ<29>")
	)
	(segment
		(start 86.647274 -214.203534)
		(end 86.647274 -214.033608)
		(width 0.1016)
		(layer "F.Cu")
		(net "M_A_CPU1_SB_DQ<29>")
	)
	(segment
		(start 55.355236 -196.718428)
		(end 55.583328 -196.490336)
		(width 0.20066)
		(layer "F.Cu")
		(net "M_A_CPU1_SB_DQ<29>")
	)
	(segment
		(start 58.858912 -196.041518)
		(end 59.284108 -196.466714)
		(width 0.20066)
		(layer "F.Cu")
		(net "M_A_CPU1_SB_DQ<29>")
	)
	(segment
		(start 66.976244 -196.55409)
		(end 66.463672 -196.041518)
		(width 0.20066)
		(layer "F.Cu")
		(net "M_A_CPU1_SB_DQ<29>")
	)
	(segment
		(start 85.795866 -219.228162)
		(end 84.981796 -219.032582)
		(width 0.088646)
		(layer "F.Cu")
		(net "M_A_CPU1_SB_DQ<29>")
	)
	(segment
		(start 63.613284 -196.035168)
		(end 63.181738 -196.466714)
		(width 0.20066)
		(layer "F.Cu")
		(net "M_A_CPU1_SB_DQ<29>")
	)
	(segment
		(start 59.284108 -196.466714)
		(end 60.947046 -196.466714)
		(width 0.20066)
		(layer "F.Cu")
		(net "M_A_CPU1_SB_DQ<29>")
	)
	(segment
		(start 53.403246 -196.466714)
		(end 54.713378 -196.466714)
		(width 0.20066)
		(layer "F.Cu")
		(net "M_A_CPU1_SB_DQ<29>")
	)
	(segment
		(start 85.807296 -215.043512)
		(end 86.647274 -214.203534)
		(width 0.1016)
		(layer "F.Cu")
		(net "M_A_CPU1_SB_DQ<29>")
	)
	(segment
		(start 84.448904 -216.17051)
		(end 85.575902 -215.043512)
		(width 0.1016)
		(layer "F.Cu")
		(net "M_A_CPU1_SB_DQ<29>")
	)
	(segment
		(start 86.647274 -209.472022)
		(end 86.070186 -208.079086)
		(width 0.20066)
		(layer "F.Cu")
		(net "M_A_CPU1_SB_DQ<29>")
	)
	(segment
		(start 63.926212 -196.035168)
		(end 63.613284 -196.035168)
		(width 0.20066)
		(layer "F.Cu")
		(net "M_A_CPU1_SB_DQ<29>")
	)
	(segment
		(start 66.463672 -196.041518)
		(end 66.237612 -196.041518)
		(width 0.20066)
		(layer "F.Cu")
		(net "M_A_CPU1_SB_DQ<29>")
	)
	(segment
		(start 84.448904 -218.49969)
		(end 84.448904 -216.17051)
		(width 0.1016)
		(layer "F.Cu")
		(net "M_A_CPU1_SB_DQ<29>")
	)
	(segment
		(start 86.070186 -208.079086)
		(end 75.761596 -197.770496)
		(width 0.20066)
		(layer "F.Cu")
		(net "M_A_CPU1_SB_DQ<29>")
	)
	(segment
		(start 85.575902 -215.043512)
		(end 85.807296 -215.043512)
		(width 0.1016)
		(layer "F.Cu")
		(net "M_A_CPU1_SB_DQ<29>")
	)
	(segment
		(start 85.367622 -214.033608)
		(end 85.367622 -209.726276)
		(width 0.20066)
		(layer "F.Cu")
		(net "M_A_CPU1_SB_DQ<28>")
	)
	(segment
		(start 83.839304 -218.755722)
		(end 83.839304 -215.91651)
		(width 0.1016)
		(layer "F.Cu")
		(net "M_A_CPU1_SB_DQ<28>")
	)
	(segment
		(start 56.40324 -197.741794)
		(end 58.373518 -197.741794)
		(width 0.1016)
		(layer "F.Cu")
		(net "M_A_CPU1_SB_DQ<28>")
	)
	(segment
		(start 84.379816 -219.296234)
		(end 83.839304 -218.755722)
		(width 0.1016)
		(layer "F.Cu")
		(net "M_A_CPU1_SB_DQ<28>")
	)
	(segment
		(start 56.37911 -197.734428)
		(end 56.40324 -197.741794)
		(width 0.1016)
		(layer "F.Cu")
		(net "M_A_CPU1_SB_DQ<28>")
	)
	(segment
		(start 85.0646 -219.78239)
		(end 84.865972 -219.78239)
		(width 0.088646)
		(layer "F.Cu")
		(net "M_A_CPU1_SB_DQ<28>")
	)
	(segment
		(start 63.900812 -197.73265)
		(end 63.26124 -197.73265)
		(width 0.20066)
		(layer "F.Cu")
		(net "M_A_CPU1_SB_DQ<28>")
	)
	(segment
		(start 59.357006 -198.166736)
		(end 60.947046 -198.166736)
		(width 0.20066)
		(layer "F.Cu")
		(net "M_A_CPU1_SB_DQ<28>")
	)
	(segment
		(start 84.865972 -219.78239)
		(end 84.379816 -219.296234)
		(width 0.088646)
		(layer "F.Cu")
		(net "M_A_CPU1_SB_DQ<28>")
	)
	(segment
		(start 55.769764 -197.734428)
		(end 56.37911 -197.734428)
		(width 0.20066)
		(layer "F.Cu")
		(net "M_A_CPU1_SB_DQ<28>")
	)
	(segment
		(start 85.367622 -209.726276)
		(end 84.985352 -208.803494)
		(width 0.20066)
		(layer "F.Cu")
		(net "M_A_CPU1_SB_DQ<28>")
	)
	(segment
		(start 54.98973 -198.418958)
		(end 55.384446 -198.418958)
		(width 0.20066)
		(layer "F.Cu")
		(net "M_A_CPU1_SB_DQ<28>")
	)
	(segment
		(start 58.932064 -197.741794)
		(end 59.357006 -198.166736)
		(width 0.20066)
		(layer "F.Cu")
		(net "M_A_CPU1_SB_DQ<28>")
	)
	(segment
		(start 66.234818 -197.74154)
		(end 64.185292 -197.74154)
		(width 0.1016)
		(layer "F.Cu")
		(net "M_A_CPU1_SB_DQ<28>")
	)
	(segment
		(start 66.667126 -197.99046)
		(end 66.418206 -197.74154)
		(width 0.20066)
		(layer "F.Cu")
		(net "M_A_CPU1_SB_DQ<28>")
	)
	(segment
		(start 84.985352 -208.803494)
		(end 75.037188 -198.85533)
		(width 0.20066)
		(layer "F.Cu")
		(net "M_A_CPU1_SB_DQ<28>")
	)
	(segment
		(start 53.403246 -198.166736)
		(end 54.737508 -198.166736)
		(width 0.20066)
		(layer "F.Cu")
		(net "M_A_CPU1_SB_DQ<28>")
	)
	(segment
		(start 64.185292 -197.74154)
		(end 63.909702 -197.74154)
		(width 0.101854)
		(layer "F.Cu")
		(net "M_A_CPU1_SB_DQ<28>")
	)
	(segment
		(start 62.827154 -198.166736)
		(end 60.947046 -198.166736)
		(width 0.20066)
		(layer "F.Cu")
		(net "M_A_CPU1_SB_DQ<28>")
	)
	(segment
		(start 54.737508 -198.166736)
		(end 54.98973 -198.418958)
		(width 0.20066)
		(layer "F.Cu")
		(net "M_A_CPU1_SB_DQ<28>")
	)
	(segment
		(start 55.384446 -198.418958)
		(end 55.607712 -198.195692)
		(width 0.20066)
		(layer "F.Cu")
		(net "M_A_CPU1_SB_DQ<28>")
	)
	(segment
		(start 55.607712 -197.89648)
		(end 55.769764 -197.734428)
		(width 0.20066)
		(layer "F.Cu")
		(net "M_A_CPU1_SB_DQ<28>")
	)
	(segment
		(start 66.418206 -197.74154)
		(end 66.237612 -197.74154)
		(width 0.20066)
		(layer "F.Cu")
		(net "M_A_CPU1_SB_DQ<28>")
	)
	(segment
		(start 85.325712 -220.041978)
		(end 85.0646 -219.78239)
		(width 0.088646)
		(layer "F.Cu")
		(net "M_A_CPU1_SB_DQ<28>")
	)
	(segment
		(start 72.949308 -197.99046)
		(end 66.667126 -197.99046)
		(width 0.20066)
		(layer "F.Cu")
		(net "M_A_CPU1_SB_DQ<28>")
	)
	(segment
		(start 85.367622 -214.388192)
		(end 85.367622 -214.033608)
		(width 0.1016)
		(layer "F.Cu")
		(net "M_A_CPU1_SB_DQ<28>")
	)
	(segment
		(start 83.839304 -215.91651)
		(end 85.367622 -214.388192)
		(width 0.1016)
		(layer "F.Cu")
		(net "M_A_CPU1_SB_DQ<28>")
	)
	(segment
		(start 63.26124 -197.73265)
		(end 62.827154 -198.166736)
		(width 0.20066)
		(layer "F.Cu")
		(net "M_A_CPU1_SB_DQ<28>")
	)
	(segment
		(start 66.237612 -197.74154)
		(end 66.234818 -197.74154)
		(width 0.101854)
		(layer "F.Cu")
		(net "M_A_CPU1_SB_DQ<28>")
	)
	(segment
		(start 75.037188 -198.85533)
		(end 72.949308 -197.99046)
		(width 0.20066)
		(layer "F.Cu")
		(net "M_A_CPU1_SB_DQ<28>")
	)
	(segment
		(start 58.704226 -197.741794)
		(end 58.932064 -197.741794)
		(width 0.20066)
		(layer "F.Cu")
		(net "M_A_CPU1_SB_DQ<28>")
	)
	(segment
		(start 55.607712 -198.195692)
		(end 55.607712 -197.89648)
		(width 0.20066)
		(layer "F.Cu")
		(net "M_A_CPU1_SB_DQ<28>")
	)
	(segment
		(start 58.373518 -197.741794)
		(end 58.704226 -197.741794)
		(width 0.101854)
		(layer "F.Cu")
		(net "M_A_CPU1_SB_DQ<28>")
	)
	(segment
		(start 63.909702 -197.74154)
		(end 63.900812 -197.73265)
		(width 0.101854)
		(layer "F.Cu")
		(net "M_A_CPU1_SB_DQ<28>")
	)
	(segment
		(start 86.714838 -221.504256)
		(end 86.441788 -221.346268)
		(width 0.088646)
		(layer "F.Cu")
		(net "M_A_CPU1_SB_DQ<27>")
	)
	(segment
		(start 64.472312 -201.566526)
		(end 64.472566 -201.56678)
		(width 0.20066)
		(layer "F.Cu")
		(net "M_A_CPU1_SB_DQ<27>")
	)
	(segment
		(start 63.768478 -201.908664)
		(end 64.130174 -201.908664)
		(width 0.20066)
		(layer "F.Cu")
		(net "M_A_CPU1_SB_DQ<27>")
	)
	(segment
		(start 84.859622 -221.442026)
		(end 84.36356 -221.442026)
		(width 0.088646)
		(layer "F.Cu")
		(net "M_A_CPU1_SB_DQ<27>")
	)
	(segment
		(start 82.791808 -210.603846)
		(end 76.056998 -203.869036)
		(width 0.20066)
		(layer "F.Cu")
		(net "M_A_CPU1_SB_DQ<27>")
	)
	(segment
		(start 85.07222 -221.345506)
		(end 84.944458 -221.419166)
		(width 0.088646)
		(layer "F.Cu")
		(net "M_A_CPU1_SB_DQ<27>")
	)
	(segment
		(start 65.548764 -201.566526)
		(end 65.54851 -201.56678)
		(width 0.20066)
		(layer "F.Cu")
		(net "M_A_CPU1_SB_DQ<27>")
	)
	(segment
		(start 75.270614 -203.366116)
		(end 75.270614 -203.082652)
		(width 0.20066)
		(layer "F.Cu")
		(net "M_A_CPU1_SB_DQ<27>")
	)
	(segment
		(start 82.315304 -219.39377)
		(end 82.315304 -215.278462)
		(width 0.1016)
		(layer "F.Cu")
		(net "M_A_CPU1_SB_DQ<27>")
	)
	(segment
		(start 86.821264 -221.504256)
		(end 86.714838 -221.504256)
		(width 0.088646)
		(layer "F.Cu")
		(net "M_A_CPU1_SB_DQ<27>")
	)
	(segment
		(start 73.838054 -202.786488)
		(end 74.264774 -202.360276)
		(width 0.20066)
		(layer "F.Cu")
		(net "M_A_CPU1_SB_DQ<27>")
	)
	(segment
		(start 85.912706 -221.345506)
		(end 85.51291 -221.345506)
		(width 0.088646)
		(layer "F.Cu")
		(net "M_A_CPU1_SB_DQ<27>")
	)
	(segment
		(start 82.791808 -214.801958)
		(end 82.791808 -214.033608)
		(width 0.1016)
		(layer "F.Cu")
		(net "M_A_CPU1_SB_DQ<27>")
	)
	(segment
		(start 87.647526 -221.307152)
		(end 87.554562 -221.214188)
		(width 0.088646)
		(layer "F.Cu")
		(net "M_A_CPU1_SB_DQ<27>")
	)
	(segment
		(start 82.315304 -215.278462)
		(end 82.791808 -214.801958)
		(width 0.1016)
		(layer "F.Cu")
		(net "M_A_CPU1_SB_DQ<27>")
	)
	(segment
		(start 59.862212 -201.991722)
		(end 62.113414 -201.991722)
		(width 0.1016)
		(layer "F.Cu")
		(net "M_A_CPU1_SB_DQ<27>")
	)
	(segment
		(start 75.270614 -203.082652)
		(end 75.051158 -202.863196)
		(width 0.20066)
		(layer "F.Cu")
		(net "M_A_CPU1_SB_DQ<27>")
	)
	(segment
		(start 75.773534 -203.869036)
		(end 75.346814 -204.295248)
		(width 0.20066)
		(layer "F.Cu")
		(net "M_A_CPU1_SB_DQ<27>")
	)
	(segment
		(start 87.554562 -221.214188)
		(end 87.354664 -221.214188)
		(width 0.088646)
		(layer "F.Cu")
		(net "M_A_CPU1_SB_DQ<27>")
	)
	(segment
		(start 74.844148 -203.792074)
		(end 75.270614 -203.366116)
		(width 0.20066)
		(layer "F.Cu")
		(net "M_A_CPU1_SB_DQ<27>")
	)
	(segment
		(start 73.733914 -201.545952)
		(end 66.868548 -201.545952)
		(width 0.20066)
		(layer "F.Cu")
		(net "M_A_CPU1_SB_DQ<27>")
	)
	(segment
		(start 74.264774 -202.076812)
		(end 73.733914 -201.545952)
		(width 0.20066)
		(layer "F.Cu")
		(net "M_A_CPU1_SB_DQ<27>")
	)
	(segment
		(start 84.175092 -221.253558)
		(end 82.315304 -219.39377)
		(width 0.1016)
		(layer "F.Cu")
		(net "M_A_CPU1_SB_DQ<27>")
	)
	(segment
		(start 73.838054 -203.069952)
		(end 73.838054 -202.786488)
		(width 0.20066)
		(layer "F.Cu")
		(net "M_A_CPU1_SB_DQ<27>")
	)
	(segment
		(start 74.264774 -202.360276)
		(end 74.264774 -202.076812)
		(width 0.20066)
		(layer "F.Cu")
		(net "M_A_CPU1_SB_DQ<27>")
	)
	(segment
		(start 65.54851 -201.56678)
		(end 65.047114 -201.56678)
		(width 0.20066)
		(layer "F.Cu")
		(net "M_A_CPU1_SB_DQ<27>")
	)
	(segment
		(start 87.45855 -221.638368)
		(end 87.647526 -221.449392)
		(width 0.088646)
		(layer "F.Cu")
		(net "M_A_CPU1_SB_DQ<27>")
	)
	(segment
		(start 62.382908 -202.026266)
		(end 62.922404 -201.48677)
		(width 0.20066)
		(layer "F.Cu")
		(net "M_A_CPU1_SB_DQ<27>")
	)
	(segment
		(start 62.147958 -202.026266)
		(end 62.382908 -202.026266)
		(width 0.20066)
		(layer "F.Cu")
		(net "M_A_CPU1_SB_DQ<27>")
	)
	(segment
		(start 66.646298 -201.768202)
		(end 65.75044 -201.768202)
		(width 0.20066)
		(layer "F.Cu")
		(net "M_A_CPU1_SB_DQ<27>")
	)
	(segment
		(start 76.056998 -203.869036)
		(end 75.773534 -203.869036)
		(width 0.20066)
		(layer "F.Cu")
		(net "M_A_CPU1_SB_DQ<27>")
	)
	(segment
		(start 87.205312 -221.669864)
		(end 87.236808 -221.638368)
		(width 0.088646)
		(layer "F.Cu")
		(net "M_A_CPU1_SB_DQ<27>")
	)
	(segment
		(start 59.627008 -202.007724)
		(end 59.822842 -202.007724)
		(width 0.20066)
		(layer "F.Cu")
		(net "M_A_CPU1_SB_DQ<27>")
	)
	(segment
		(start 63.346584 -201.48677)
		(end 63.768478 -201.908664)
		(width 0.20066)
		(layer "F.Cu")
		(net "M_A_CPU1_SB_DQ<27>")
	)
	(segment
		(start 57.503314 -201.56678)
		(end 59.186064 -201.56678)
		(width 0.20066)
		(layer "F.Cu")
		(net "M_A_CPU1_SB_DQ<27>")
	)
	(segment
		(start 82.791808 -214.033608)
		(end 82.791808 -210.603846)
		(width 0.20066)
		(layer "F.Cu")
		(net "M_A_CPU1_SB_DQ<27>")
	)
	(segment
		(start 65.75044 -201.768202)
		(end 65.548764 -201.566526)
		(width 0.20066)
		(layer "F.Cu")
		(net "M_A_CPU1_SB_DQ<27>")
	)
	(segment
		(start 87.647526 -221.449392)
		(end 87.647526 -221.307152)
		(width 0.088646)
		(layer "F.Cu")
		(net "M_A_CPU1_SB_DQ<27>")
	)
	(segment
		(start 59.186064 -201.56678)
		(end 59.627008 -202.007724)
		(width 0.20066)
		(layer "F.Cu")
		(net "M_A_CPU1_SB_DQ<27>")
	)
	(segment
		(start 62.922404 -201.48677)
		(end 63.346584 -201.48677)
		(width 0.20066)
		(layer "F.Cu")
		(net "M_A_CPU1_SB_DQ<27>")
	)
	(segment
		(start 74.340974 -203.289408)
		(end 74.05751 -203.289408)
		(width 0.20066)
		(layer "F.Cu")
		(net "M_A_CPU1_SB_DQ<27>")
	)
	(segment
		(start 75.063604 -204.295248)
		(end 74.844148 -204.075792)
		(width 0.20066)
		(layer "F.Cu")
		(net "M_A_CPU1_SB_DQ<27>")
	)
	(segment
		(start 87.354664 -221.214188)
		(end 86.938612 -221.386908)
		(width 0.088646)
		(layer "F.Cu")
		(net "M_A_CPU1_SB_DQ<27>")
	)
	(segment
		(start 84.36356 -221.442026)
		(end 84.175092 -221.253558)
		(width 0.088646)
		(layer "F.Cu")
		(net "M_A_CPU1_SB_DQ<27>")
	)
	(segment
		(start 74.05751 -203.289408)
		(end 73.838054 -203.069952)
		(width 0.20066)
		(layer "F.Cu")
		(net "M_A_CPU1_SB_DQ<27>")
	)
	(segment
		(start 64.472566 -201.56678)
		(end 65.047114 -201.56678)
		(width 0.20066)
		(layer "F.Cu")
		(net "M_A_CPU1_SB_DQ<27>")
	)
	(segment
		(start 87.236808 -221.638368)
		(end 87.45855 -221.638368)
		(width 0.088646)
		(layer "F.Cu")
		(net "M_A_CPU1_SB_DQ<27>")
	)
	(segment
		(start 75.346814 -204.295248)
		(end 75.063604 -204.295248)
		(width 0.20066)
		(layer "F.Cu")
		(net "M_A_CPU1_SB_DQ<27>")
	)
	(segment
		(start 74.767694 -202.863196)
		(end 74.340974 -203.289408)
		(width 0.20066)
		(layer "F.Cu")
		(net "M_A_CPU1_SB_DQ<27>")
	)
	(segment
		(start 74.844148 -204.075792)
		(end 74.844148 -203.792074)
		(width 0.20066)
		(layer "F.Cu")
		(net "M_A_CPU1_SB_DQ<27>")
	)
	(segment
		(start 86.314026 -221.300802)
		(end 86.248494 -221.23527)
		(width 0.088646)
		(layer "F.Cu")
		(net "M_A_CPU1_SB_DQ<27>")
	)
	(segment
		(start 62.113414 -201.991722)
		(end 62.147958 -202.026266)
		(width 0.1016)
		(layer "F.Cu")
		(net "M_A_CPU1_SB_DQ<27>")
	)
	(segment
		(start 59.822842 -202.007724)
		(end 59.84621 -202.007724)
		(width 0.101854)
		(layer "F.Cu")
		(net "M_A_CPU1_SB_DQ<27>")
	)
	(segment
		(start 66.868548 -201.545952)
		(end 66.646298 -201.768202)
		(width 0.20066)
		(layer "F.Cu")
		(net "M_A_CPU1_SB_DQ<27>")
	)
	(segment
		(start 75.051158 -202.863196)
		(end 74.767694 -202.863196)
		(width 0.20066)
		(layer "F.Cu")
		(net "M_A_CPU1_SB_DQ<27>")
	)
	(segment
		(start 59.84621 -202.007724)
		(end 59.862212 -201.991722)
		(width 0.101854)
		(layer "F.Cu")
		(net "M_A_CPU1_SB_DQ<27>")
	)
	(segment
		(start 86.938612 -221.386908)
		(end 86.821264 -221.504256)
		(width 0.088646)
		(layer "F.Cu")
		(net "M_A_CPU1_SB_DQ<27>")
	)
	(segment
		(start 86.022942 -221.23527)
		(end 85.912706 -221.345506)
		(width 0.088646)
		(layer "F.Cu")
		(net "M_A_CPU1_SB_DQ<27>")
	)
	(segment
		(start 86.248494 -221.23527)
		(end 86.022942 -221.23527)
		(width 0.088646)
		(layer "F.Cu")
		(net "M_A_CPU1_SB_DQ<27>")
	)
	(segment
		(start 64.130174 -201.908664)
		(end 64.472312 -201.566526)
		(width 0.20066)
		(layer "F.Cu")
		(net "M_A_CPU1_SB_DQ<27>")
	)
	(arc
		(start 86.441788 -221.346268)
		(mid 86.379984 -221.317697)
		(end 86.314026 -221.300802)
		(width 0.088646)
		(layer "F.Cu")
		(net "M_A_CPU1_SB_DQ<27>")
	)
	(arc
		(start 85.51291 -221.345506)
		(mid 85.292548 -221.286416)
		(end 85.07222 -221.345506)
		(width 0.088646)
		(layer "F.Cu")
		(net "M_A_CPU1_SB_DQ<27>")
	)
	(arc
		(start 84.944458 -221.419166)
		(mid 84.903546 -221.43619)
		(end 84.859622 -221.442026)
		(width 0.088646)
		(layer "F.Cu")
		(net "M_A_CPU1_SB_DQ<27>")
	)
	(segment
		(start 79.004414 -208.909412)
		(end 78.578456 -209.33537)
		(width 0.20066)
		(layer "F.Cu")
		(net "M_A_CPU1_SB_DQ<26>")
	)
	(segment
		(start 79.584296 -210.34121)
		(end 79.300324 -210.34121)
		(width 0.20066)
		(layer "F.Cu")
		(net "M_A_CPU1_SB_DQ<26>")
	)
	(segment
		(start 80.513174 -210.418172)
		(end 80.513174 -210.1342)
		(width 0.20066)
		(layer "F.Cu")
		(net "M_A_CPU1_SB_DQ<26>")
	)
	(segment
		(start 84.86267 -221.942152)
		(end 84.612226 -221.928182)
		(width 0.088646)
		(layer "F.Cu")
		(net "M_A_CPU1_SB_DQ<26>")
	)
	(segment
		(start 81.51241 -211.146644)
		(end 81.293462 -210.927696)
		(width 0.20066)
		(layer "F.Cu")
		(net "M_A_CPU1_SB_DQ<26>")
	)
	(segment
		(start 81.705704 -214.38743)
		(end 81.51241 -214.194136)
		(width 0.1016)
		(layer "F.Cu")
		(net "M_A_CPU1_SB_DQ<26>")
	)
	(segment
		(start 79.081376 -210.122262)
		(end 79.081376 -209.83829)
		(width 0.20066)
		(layer "F.Cu")
		(net "M_A_CPU1_SB_DQ<26>")
	)
	(segment
		(start 80.087216 -211.128102)
		(end 80.087216 -210.84413)
		(width 0.20066)
		(layer "F.Cu")
		(net "M_A_CPU1_SB_DQ<26>")
	)
	(segment
		(start 81.00949 -210.927696)
		(end 80.590136 -211.34705)
		(width 0.20066)
		(layer "F.Cu")
		(net "M_A_CPU1_SB_DQ<26>")
	)
	(segment
		(start 57.503314 -203.266802)
		(end 59.178698 -203.266802)
		(width 0.20066)
		(layer "F.Cu")
		(net "M_A_CPU1_SB_DQ<26>")
	)
	(segment
		(start 59.178698 -203.266802)
		(end 59.622436 -203.71054)
		(width 0.20066)
		(layer "F.Cu")
		(net "M_A_CPU1_SB_DQ<26>")
	)
	(segment
		(start 85.974428 -221.960186)
		(end 85.884512 -221.87027)
		(width 0.088646)
		(layer "F.Cu")
		(net "M_A_CPU1_SB_DQ<26>")
	)
	(segment
		(start 62.097412 -203.691744)
		(end 62.147958 -203.691744)
		(width 0.101854)
		(layer "F.Cu")
		(net "M_A_CPU1_SB_DQ<26>")
	)
	(segment
		(start 81.293462 -210.927696)
		(end 81.00949 -210.927696)
		(width 0.20066)
		(layer "F.Cu")
		(net "M_A_CPU1_SB_DQ<26>")
	)
	(segment
		(start 79.507334 -209.412332)
		(end 79.507334 -209.12836)
		(width 0.20066)
		(layer "F.Cu")
		(net "M_A_CPU1_SB_DQ<26>")
	)
	(segment
		(start 78.294484 -209.33537)
		(end 78.075536 -209.116422)
		(width 0.20066)
		(layer "F.Cu")
		(net "M_A_CPU1_SB_DQ<26>")
	)
	(segment
		(start 66.435224 -203.266802)
		(end 65.047114 -203.266802)
		(width 0.20066)
		(layer "F.Cu")
		(net "M_A_CPU1_SB_DQ<26>")
	)
	(segment
		(start 78.501494 -208.406492)
		(end 78.501494 -208.12252)
		(width 0.20066)
		(layer "F.Cu")
		(net "M_A_CPU1_SB_DQ<26>")
	)
	(segment
		(start 63.33363 -203.266802)
		(end 65.047114 -203.266802)
		(width 0.20066)
		(layer "F.Cu")
		(net "M_A_CPU1_SB_DQ<26>")
	)
	(segment
		(start 79.081376 -209.83829)
		(end 79.507334 -209.412332)
		(width 0.20066)
		(layer "F.Cu")
		(net "M_A_CPU1_SB_DQ<26>")
	)
	(segment
		(start 86.735666 -222.48368)
		(end 86.557612 -222.30715)
		(width 0.088646)
		(layer "F.Cu")
		(net "M_A_CPU1_SB_DQ<26>")
	)
	(segment
		(start 85.634322 -221.992952)
		(end 85.634322 -222.039434)
		(width 0.088646)
		(layer "F.Cu")
		(net "M_A_CPU1_SB_DQ<26>")
	)
	(segment
		(start 78.578456 -209.33537)
		(end 78.294484 -209.33537)
		(width 0.20066)
		(layer "F.Cu")
		(net "M_A_CPU1_SB_DQ<26>")
	)
	(segment
		(start 62.646814 -203.557378)
		(end 62.646814 -203.20762)
		(width 0.20066)
		(layer "F.Cu")
		(net "M_A_CPU1_SB_DQ<26>")
	)
	(segment
		(start 85.757004 -221.87027)
		(end 85.634322 -221.992952)
		(width 0.088646)
		(layer "F.Cu")
		(net "M_A_CPU1_SB_DQ<26>")
	)
	(segment
		(start 62.512448 -203.691744)
		(end 62.646814 -203.557378)
		(width 0.20066)
		(layer "F.Cu")
		(net "M_A_CPU1_SB_DQ<26>")
	)
	(segment
		(start 85.884512 -221.87027)
		(end 85.757004 -221.87027)
		(width 0.088646)
		(layer "F.Cu")
		(net "M_A_CPU1_SB_DQ<26>")
	)
	(segment
		(start 80.294226 -209.915252)
		(end 80.010254 -209.915252)
		(width 0.20066)
		(layer "F.Cu")
		(net "M_A_CPU1_SB_DQ<26>")
	)
	(segment
		(start 86.557612 -222.30715)
		(end 86.19363 -222.30715)
		(width 0.088646)
		(layer "F.Cu")
		(net "M_A_CPU1_SB_DQ<26>")
	)
	(segment
		(start 81.705704 -219.646754)
		(end 81.705704 -214.38743)
		(width 0.1016)
		(layer "F.Cu")
		(net "M_A_CPU1_SB_DQ<26>")
	)
	(segment
		(start 59.622436 -203.71054)
		(end 59.819286 -203.71054)
		(width 0.20066)
		(layer "F.Cu")
		(net "M_A_CPU1_SB_DQ<26>")
	)
	(segment
		(start 80.306164 -211.34705)
		(end 80.087216 -211.128102)
		(width 0.20066)
		(layer "F.Cu")
		(net "M_A_CPU1_SB_DQ<26>")
	)
	(segment
		(start 79.300324 -210.34121)
		(end 79.081376 -210.122262)
		(width 0.20066)
		(layer "F.Cu")
		(net "M_A_CPU1_SB_DQ<26>")
	)
	(segment
		(start 62.147958 -203.691744)
		(end 62.512448 -203.691744)
		(width 0.20066)
		(layer "F.Cu")
		(net "M_A_CPU1_SB_DQ<26>")
	)
	(segment
		(start 62.646814 -203.20762)
		(end 62.774322 -203.080112)
		(width 0.20066)
		(layer "F.Cu")
		(net "M_A_CPU1_SB_DQ<26>")
	)
	(segment
		(start 81.51241 -211.430616)
		(end 81.51241 -211.146644)
		(width 0.20066)
		(layer "F.Cu")
		(net "M_A_CPU1_SB_DQ<26>")
	)
	(segment
		(start 83.934554 -221.875604)
		(end 83.7438 -221.68485)
		(width 0.088646)
		(layer "F.Cu")
		(net "M_A_CPU1_SB_DQ<26>")
	)
	(segment
		(start 67.113658 -203.131928)
		(end 66.903092 -203.173838)
		(width 0.20066)
		(layer "F.Cu")
		(net "M_A_CPU1_SB_DQ<26>")
	)
	(segment
		(start 81.51241 -212.553296)
		(end 81.093056 -212.133942)
		(width 0.20066)
		(layer "F.Cu")
		(net "M_A_CPU1_SB_DQ<26>")
	)
	(segment
		(start 85.634322 -222.039434)
		(end 85.542628 -222.131128)
		(width 0.088646)
		(layer "F.Cu")
		(net "M_A_CPU1_SB_DQ<26>")
	)
	(segment
		(start 86.19363 -222.30715)
		(end 85.974428 -222.087948)
		(width 0.088646)
		(layer "F.Cu")
		(net "M_A_CPU1_SB_DQ<26>")
	)
	(segment
		(start 79.507334 -209.12836)
		(end 79.288386 -208.909412)
		(width 0.20066)
		(layer "F.Cu")
		(net "M_A_CPU1_SB_DQ<26>")
	)
	(segment
		(start 81.093056 -211.84997)
		(end 81.51241 -211.430616)
		(width 0.20066)
		(layer "F.Cu")
		(net "M_A_CPU1_SB_DQ<26>")
	)
	(segment
		(start 80.590136 -211.34705)
		(end 80.306164 -211.34705)
		(width 0.20066)
		(layer "F.Cu")
		(net "M_A_CPU1_SB_DQ<26>")
	)
	(segment
		(start 80.513174 -210.1342)
		(end 80.294226 -209.915252)
		(width 0.20066)
		(layer "F.Cu")
		(net "M_A_CPU1_SB_DQ<26>")
	)
	(segment
		(start 85.15223 -222.009716)
		(end 84.86267 -221.942152)
		(width 0.088646)
		(layer "F.Cu")
		(net "M_A_CPU1_SB_DQ<26>")
	)
	(segment
		(start 79.288386 -208.909412)
		(end 79.004414 -208.909412)
		(width 0.20066)
		(layer "F.Cu")
		(net "M_A_CPU1_SB_DQ<26>")
	)
	(segment
		(start 77.998574 -207.903572)
		(end 77.572616 -208.32953)
		(width 0.20066)
		(layer "F.Cu")
		(net "M_A_CPU1_SB_DQ<26>")
	)
	(segment
		(start 85.542628 -222.131128)
		(end 85.386418 -222.131128)
		(width 0.088646)
		(layer "F.Cu")
		(net "M_A_CPU1_SB_DQ<26>")
	)
	(segment
		(start 81.51241 -214.194136)
		(end 81.51241 -214.033862)
		(width 0.1016)
		(layer "F.Cu")
		(net "M_A_CPU1_SB_DQ<26>")
	)
	(segment
		(start 66.903092 -203.173838)
		(end 66.435224 -203.266802)
		(width 0.20066)
		(layer "F.Cu")
		(net "M_A_CPU1_SB_DQ<26>")
	)
	(segment
		(start 85.974428 -222.087948)
		(end 85.974428 -221.960186)
		(width 0.088646)
		(layer "F.Cu")
		(net "M_A_CPU1_SB_DQ<26>")
	)
	(segment
		(start 81.093056 -212.133942)
		(end 81.093056 -211.84997)
		(width 0.20066)
		(layer "F.Cu")
		(net "M_A_CPU1_SB_DQ<26>")
	)
	(segment
		(start 59.819286 -203.71054)
		(end 59.822842 -203.706984)
		(width 0.20066)
		(layer "F.Cu")
		(net "M_A_CPU1_SB_DQ<26>")
	)
	(segment
		(start 67.39382 -202.851766)
		(end 67.113658 -203.131928)
		(width 0.20066)
		(layer "F.Cu")
		(net "M_A_CPU1_SB_DQ<26>")
	)
	(segment
		(start 78.075536 -208.83245)
		(end 78.501494 -208.406492)
		(width 0.20066)
		(layer "F.Cu")
		(net "M_A_CPU1_SB_DQ<26>")
	)
	(segment
		(start 59.822842 -203.706984)
		(end 59.838082 -203.691744)
		(width 0.101854)
		(layer "F.Cu")
		(net "M_A_CPU1_SB_DQ<26>")
	)
	(segment
		(start 63.14694 -203.080112)
		(end 63.33363 -203.266802)
		(width 0.20066)
		(layer "F.Cu")
		(net "M_A_CPU1_SB_DQ<26>")
	)
	(segment
		(start 71.81088 -202.851766)
		(end 67.39382 -202.851766)
		(width 0.20066)
		(layer "F.Cu")
		(net "M_A_CPU1_SB_DQ<26>")
	)
	(segment
		(start 84.612226 -221.928182)
		(end 84.158582 -221.993714)
		(width 0.088646)
		(layer "F.Cu")
		(net "M_A_CPU1_SB_DQ<26>")
	)
	(segment
		(start 62.774322 -203.080112)
		(end 63.14694 -203.080112)
		(width 0.20066)
		(layer "F.Cu")
		(net "M_A_CPU1_SB_DQ<26>")
	)
	(segment
		(start 85.341968 -222.11919)
		(end 85.15223 -222.009716)
		(width 0.088646)
		(layer "F.Cu")
		(net "M_A_CPU1_SB_DQ<26>")
	)
	(segment
		(start 77.288644 -208.32953)
		(end 71.81088 -202.851766)
		(width 0.20066)
		(layer "F.Cu")
		(net "M_A_CPU1_SB_DQ<26>")
	)
	(segment
		(start 80.087216 -210.84413)
		(end 80.513174 -210.418172)
		(width 0.20066)
		(layer "F.Cu")
		(net "M_A_CPU1_SB_DQ<26>")
	)
	(segment
		(start 83.7438 -221.68485)
		(end 81.705704 -219.646754)
		(width 0.1016)
		(layer "F.Cu")
		(net "M_A_CPU1_SB_DQ<26>")
	)
	(segment
		(start 78.075536 -209.116422)
		(end 78.075536 -208.83245)
		(width 0.20066)
		(layer "F.Cu")
		(net "M_A_CPU1_SB_DQ<26>")
	)
	(segment
		(start 78.501494 -208.12252)
		(end 78.282546 -207.903572)
		(width 0.20066)
		(layer "F.Cu")
		(net "M_A_CPU1_SB_DQ<26>")
	)
	(segment
		(start 59.887612 -203.691744)
		(end 62.097412 -203.691744)
		(width 0.1016)
		(layer "F.Cu")
		(net "M_A_CPU1_SB_DQ<26>")
	)
	(segment
		(start 77.572616 -208.32953)
		(end 77.288644 -208.32953)
		(width 0.20066)
		(layer "F.Cu")
		(net "M_A_CPU1_SB_DQ<26>")
	)
	(segment
		(start 80.010254 -209.915252)
		(end 79.584296 -210.34121)
		(width 0.20066)
		(layer "F.Cu")
		(net "M_A_CPU1_SB_DQ<26>")
	)
	(segment
		(start 81.51241 -214.033862)
		(end 81.51241 -212.553296)
		(width 0.20066)
		(layer "F.Cu")
		(net "M_A_CPU1_SB_DQ<26>")
	)
	(segment
		(start 59.838082 -203.691744)
		(end 59.887612 -203.691744)
		(width 0.101854)
		(layer "F.Cu")
		(net "M_A_CPU1_SB_DQ<26>")
	)
	(segment
		(start 78.282546 -207.903572)
		(end 77.998574 -207.903572)
		(width 0.20066)
		(layer "F.Cu")
		(net "M_A_CPU1_SB_DQ<26>")
	)
	(arc
		(start 84.158582 -221.993714)
		(mid 84.037645 -221.951582)
		(end 83.934554 -221.875604)
		(width 0.088646)
		(layer "F.Cu")
		(net "M_A_CPU1_SB_DQ<26>")
	)
	(arc
		(start 85.386418 -222.131128)
		(mid 85.363407 -222.128089)
		(end 85.341968 -222.11919)
		(width 0.088646)
		(layer "F.Cu")
		(net "M_A_CPU1_SB_DQ<26>")
	)
	(segment
		(start 82.151982 -210.868514)
		(end 78.123796 -206.840328)
		(width 0.20066)
		(layer "F.Cu")
		(net "M_A_CPU1_SB_DQ<25>")
	)
	(segment
		(start 67.122548 -202.20178)
		(end 66.933064 -202.391264)
		(width 0.20066)
		(layer "F.Cu")
		(net "M_A_CPU1_SB_DQ<25>")
	)
	(segment
		(start 55.583328 -202.440794)
		(end 55.583328 -202.146154)
		(width 0.20066)
		(layer "F.Cu")
		(net "M_A_CPU1_SB_DQ<25>")
	)
	(segment
		(start 64.119506 -202.859132)
		(end 63.977012 -202.859132)
		(width 0.101854)
		(layer "F.Cu")
		(net "M_A_CPU1_SB_DQ<25>")
	)
	(segment
		(start 56.37911 -201.982832)
		(end 56.42229 -201.982832)
		(width 0.101854)
		(layer "F.Cu")
		(net "M_A_CPU1_SB_DQ<25>")
	)
	(segment
		(start 76.331064 -205.047596)
		(end 76.112116 -204.828648)
		(width 0.20066)
		(layer "F.Cu")
		(net "M_A_CPU1_SB_DQ<25>")
	)
	(segment
		(start 56.42229 -201.982832)
		(end 56.451246 -201.991722)
		(width 0.1016)
		(layer "F.Cu")
		(net "M_A_CPU1_SB_DQ<25>")
	)
	(segment
		(start 83.959446 -221.469204)
		(end 82.010504 -219.520262)
		(width 0.1016)
		(layer "F.Cu")
		(net "M_A_CPU1_SB_DQ<25>")
	)
	(segment
		(start 55.74665 -201.982832)
		(end 56.37911 -201.982832)
		(width 0.20066)
		(layer "F.Cu")
		(net "M_A_CPU1_SB_DQ<25>")
	)
	(segment
		(start 82.010504 -214.408258)
		(end 82.151982 -214.26678)
		(width 0.1016)
		(layer "F.Cu")
		(net "M_A_CPU1_SB_DQ<25>")
	)
	(segment
		(start 55.355744 -202.668378)
		(end 55.583328 -202.440794)
		(width 0.20066)
		(layer "F.Cu")
		(net "M_A_CPU1_SB_DQ<25>")
	)
	(segment
		(start 75.402186 -205.254606)
		(end 75.118214 -205.254606)
		(width 0.20066)
		(layer "F.Cu")
		(net "M_A_CPU1_SB_DQ<25>")
	)
	(segment
		(start 54.713378 -202.416664)
		(end 54.965092 -202.668378)
		(width 0.20066)
		(layer "F.Cu")
		(net "M_A_CPU1_SB_DQ<25>")
	)
	(segment
		(start 66.212212 -202.861164)
		(end 66.19113 -202.861164)
		(width 0.101854)
		(layer "F.Cu")
		(net "M_A_CPU1_SB_DQ<25>")
	)
	(segment
		(start 77.219048 -207.177132)
		(end 77.0001 -206.958184)
		(width 0.20066)
		(layer "F.Cu")
		(net "M_A_CPU1_SB_DQ<25>")
	)
	(segment
		(start 54.965092 -202.668378)
		(end 55.355744 -202.668378)
		(width 0.20066)
		(layer "F.Cu")
		(net "M_A_CPU1_SB_DQ<25>")
	)
	(segment
		(start 62.034674 -202.416664)
		(end 60.947046 -202.416664)
		(width 0.20066)
		(layer "F.Cu")
		(net "M_A_CPU1_SB_DQ<25>")
	)
	(segment
		(start 77.117956 -205.834488)
		(end 76.833984 -205.834488)
		(width 0.20066)
		(layer "F.Cu")
		(net "M_A_CPU1_SB_DQ<25>")
	)
	(segment
		(start 58.704226 -201.991722)
		(end 58.907934 -201.991722)
		(width 0.20066)
		(layer "F.Cu")
		(net "M_A_CPU1_SB_DQ<25>")
	)
	(segment
		(start 82.151982 -214.26678)
		(end 82.151982 -214.033608)
		(width 0.1016)
		(layer "F.Cu")
		(net "M_A_CPU1_SB_DQ<25>")
	)
	(segment
		(start 76.01585 -205.646782)
		(end 76.331064 -205.331568)
		(width 0.20066)
		(layer "F.Cu")
		(net "M_A_CPU1_SB_DQ<25>")
	)
	(segment
		(start 63.302134 -202.693016)
		(end 62.034674 -202.416664)
		(width 0.20066)
		(layer "F.Cu")
		(net "M_A_CPU1_SB_DQ<25>")
	)
	(segment
		(start 63.792608 -202.859132)
		(end 63.302134 -202.693016)
		(width 0.20066)
		(layer "F.Cu")
		(net "M_A_CPU1_SB_DQ<25>")
	)
	(segment
		(start 76.234798 -206.149702)
		(end 76.01585 -205.930754)
		(width 0.20066)
		(layer "F.Cu")
		(net "M_A_CPU1_SB_DQ<25>")
	)
	(segment
		(start 56.451246 -201.991722)
		(end 58.646822 -201.991722)
		(width 0.1016)
		(layer "F.Cu")
		(net "M_A_CPU1_SB_DQ<25>")
	)
	(segment
		(start 66.171572 -202.841606)
		(end 64.176148 -202.841606)
		(width 0.1016)
		(layer "F.Cu")
		(net "M_A_CPU1_SB_DQ<25>")
	)
	(segment
		(start 77.336904 -206.053436)
		(end 77.117956 -205.834488)
		(width 0.20066)
		(layer "F.Cu")
		(net "M_A_CPU1_SB_DQ<25>")
	)
	(segment
		(start 76.331064 -205.331568)
		(end 76.331064 -205.047596)
		(width 0.20066)
		(layer "F.Cu")
		(net "M_A_CPU1_SB_DQ<25>")
	)
	(segment
		(start 66.81089 -202.391264)
		(end 66.34099 -202.861164)
		(width 0.20066)
		(layer "F.Cu")
		(net "M_A_CPU1_SB_DQ<25>")
	)
	(segment
		(start 76.112116 -204.828648)
		(end 75.828144 -204.828648)
		(width 0.20066)
		(layer "F.Cu")
		(net "M_A_CPU1_SB_DQ<25>")
	)
	(segment
		(start 55.583328 -202.146154)
		(end 55.74665 -201.982832)
		(width 0.20066)
		(layer "F.Cu")
		(net "M_A_CPU1_SB_DQ<25>")
	)
	(segment
		(start 53.403246 -202.416664)
		(end 54.713378 -202.416664)
		(width 0.20066)
		(layer "F.Cu")
		(net "M_A_CPU1_SB_DQ<25>")
	)
	(segment
		(start 77.50302 -207.177132)
		(end 77.219048 -207.177132)
		(width 0.20066)
		(layer "F.Cu")
		(net "M_A_CPU1_SB_DQ<25>")
	)
	(segment
		(start 77.336904 -206.337408)
		(end 77.336904 -206.053436)
		(width 0.20066)
		(layer "F.Cu")
		(net "M_A_CPU1_SB_DQ<25>")
	)
	(segment
		(start 75.118214 -205.254606)
		(end 72.065388 -202.20178)
		(width 0.20066)
		(layer "F.Cu")
		(net "M_A_CPU1_SB_DQ<25>")
	)
	(segment
		(start 66.933064 -202.391264)
		(end 66.81089 -202.391264)
		(width 0.20066)
		(layer "F.Cu")
		(net "M_A_CPU1_SB_DQ<25>")
	)
	(segment
		(start 58.646822 -201.991722)
		(end 58.704226 -201.991722)
		(width 0.101854)
		(layer "F.Cu")
		(net "M_A_CPU1_SB_DQ<25>")
	)
	(segment
		(start 77.0001 -206.958184)
		(end 77.0001 -206.674212)
		(width 0.20066)
		(layer "F.Cu")
		(net "M_A_CPU1_SB_DQ<25>")
	)
	(segment
		(start 82.010504 -219.520262)
		(end 82.010504 -214.408258)
		(width 0.1016)
		(layer "F.Cu")
		(net "M_A_CPU1_SB_DQ<25>")
	)
	(segment
		(start 72.065388 -202.20178)
		(end 67.122548 -202.20178)
		(width 0.20066)
		(layer "F.Cu")
		(net "M_A_CPU1_SB_DQ<25>")
	)
	(segment
		(start 64.176148 -202.841606)
		(end 64.119506 -202.859132)
		(width 0.1016)
		(layer "F.Cu")
		(net "M_A_CPU1_SB_DQ<25>")
	)
	(segment
		(start 76.833984 -205.834488)
		(end 76.51877 -206.149702)
		(width 0.20066)
		(layer "F.Cu")
		(net "M_A_CPU1_SB_DQ<25>")
	)
	(segment
		(start 84.161122 -221.67088)
		(end 83.959446 -221.469204)
		(width 0.088646)
		(layer "F.Cu")
		(net "M_A_CPU1_SB_DQ<25>")
	)
	(segment
		(start 76.51877 -206.149702)
		(end 76.234798 -206.149702)
		(width 0.20066)
		(layer "F.Cu")
		(net "M_A_CPU1_SB_DQ<25>")
	)
	(segment
		(start 77.0001 -206.674212)
		(end 77.336904 -206.337408)
		(width 0.20066)
		(layer "F.Cu")
		(net "M_A_CPU1_SB_DQ<25>")
	)
	(segment
		(start 59.332876 -202.416664)
		(end 60.947046 -202.416664)
		(width 0.20066)
		(layer "F.Cu")
		(net "M_A_CPU1_SB_DQ<25>")
	)
	(segment
		(start 58.907934 -201.991722)
		(end 59.332876 -202.416664)
		(width 0.20066)
		(layer "F.Cu")
		(net "M_A_CPU1_SB_DQ<25>")
	)
	(segment
		(start 66.19113 -202.861164)
		(end 66.171572 -202.841606)
		(width 0.101854)
		(layer "F.Cu")
		(net "M_A_CPU1_SB_DQ<25>")
	)
	(segment
		(start 77.839824 -206.840328)
		(end 77.50302 -207.177132)
		(width 0.20066)
		(layer "F.Cu")
		(net "M_A_CPU1_SB_DQ<25>")
	)
	(segment
		(start 76.01585 -205.930754)
		(end 76.01585 -205.646782)
		(width 0.20066)
		(layer "F.Cu")
		(net "M_A_CPU1_SB_DQ<25>")
	)
	(segment
		(start 85.325712 -221.669864)
		(end 84.161122 -221.67088)
		(width 0.088646)
		(layer "F.Cu")
		(net "M_A_CPU1_SB_DQ<25>")
	)
	(segment
		(start 66.34099 -202.861164)
		(end 66.212212 -202.861164)
		(width 0.20066)
		(layer "F.Cu")
		(net "M_A_CPU1_SB_DQ<25>")
	)
	(segment
		(start 63.977012 -202.859132)
		(end 63.792608 -202.859132)
		(width 0.20066)
		(layer "F.Cu")
		(net "M_A_CPU1_SB_DQ<25>")
	)
	(segment
		(start 82.151982 -214.033608)
		(end 82.151982 -210.868514)
		(width 0.20066)
		(layer "F.Cu")
		(net "M_A_CPU1_SB_DQ<25>")
	)
	(segment
		(start 78.123796 -206.840328)
		(end 77.839824 -206.840328)
		(width 0.20066)
		(layer "F.Cu")
		(net "M_A_CPU1_SB_DQ<25>")
	)
	(segment
		(start 75.828144 -204.828648)
		(end 75.402186 -205.254606)
		(width 0.20066)
		(layer "F.Cu")
		(net "M_A_CPU1_SB_DQ<25>")
	)
	(segment
		(start 58.704226 -203.691744)
		(end 58.907934 -203.691744)
		(width 0.20066)
		(layer "F.Cu")
		(net "M_A_CPU1_SB_DQ<24>")
	)
	(segment
		(start 69.721476 -204.466444)
		(end 69.520816 -204.265784)
		(width 0.20066)
		(layer "F.Cu")
		(net "M_A_CPU1_SB_DQ<24>")
	)
	(segment
		(start 81.18094 -215.247728)
		(end 81.400904 -215.027764)
		(width 0.1016)
		(layer "F.Cu")
		(net "M_A_CPU1_SB_DQ<24>")
	)
	(segment
		(start 70.742556 -203.507848)
		(end 70.432676 -203.507848)
		(width 0.20066)
		(layer "F.Cu")
		(net "M_A_CPU1_SB_DQ<24>")
	)
	(segment
		(start 72.130412 -204.076046)
		(end 71.844154 -204.076046)
		(width 0.20066)
		(layer "F.Cu")
		(net "M_A_CPU1_SB_DQ<24>")
	)
	(segment
		(start 67.897756 -203.507848)
		(end 67.650614 -203.507848)
		(width 0.20066)
		(layer "F.Cu")
		(net "M_A_CPU1_SB_DQ<24>")
	)
	(segment
		(start 66.161412 -203.679806)
		(end 66.13271 -203.679806)
		(width 0.101854)
		(layer "F.Cu")
		(net "M_A_CPU1_SB_DQ<24>")
	)
	(segment
		(start 83.528154 -221.900496)
		(end 81.400904 -219.773246)
		(width 0.1016)
		(layer "F.Cu")
		(net "M_A_CPU1_SB_DQ<24>")
	)
	(segment
		(start 83.933284 -222.305626)
		(end 83.528154 -221.900496)
		(width 0.088646)
		(layer "F.Cu")
		(net "M_A_CPU1_SB_DQ<24>")
	)
	(segment
		(start 66.13271 -203.679806)
		(end 66.120772 -203.691744)
		(width 0.101854)
		(layer "F.Cu")
		(net "M_A_CPU1_SB_DQ<24>")
	)
	(segment
		(start 80.872838 -214.033862)
		(end 80.872838 -212.818472)
		(width 0.20066)
		(layer "F.Cu")
		(net "M_A_CPU1_SB_DQ<24>")
	)
	(segment
		(start 64.185292 -203.691744)
		(end 64.140842 -203.67625)
		(width 0.1016)
		(layer "F.Cu")
		(net "M_A_CPU1_SB_DQ<24>")
	)
	(segment
		(start 56.37911 -203.68006)
		(end 56.41721 -203.691744)
		(width 0.1016)
		(layer "F.Cu")
		(net "M_A_CPU1_SB_DQ<24>")
	)
	(segment
		(start 71.844154 -204.076046)
		(end 71.453756 -204.466444)
		(width 0.20066)
		(layer "F.Cu")
		(net "M_A_CPU1_SB_DQ<24>")
	)
	(segment
		(start 70.031356 -204.466444)
		(end 69.721476 -204.466444)
		(width 0.20066)
		(layer "F.Cu")
		(net "M_A_CPU1_SB_DQ<24>")
	)
	(segment
		(start 68.608956 -204.466444)
		(end 68.299076 -204.466444)
		(width 0.20066)
		(layer "F.Cu")
		(net "M_A_CPU1_SB_DQ<24>")
	)
	(segment
		(start 66.57086 -203.81849)
		(end 66.238882 -203.679806)
		(width 0.20066)
		(layer "F.Cu")
		(net "M_A_CPU1_SB_DQ<24>")
	)
	(segment
		(start 85.29828 -222.314262)
		(end 85.152484 -222.229934)
		(width 0.088646)
		(layer "F.Cu")
		(net "M_A_CPU1_SB_DQ<24>")
	)
	(segment
		(start 53.403246 -204.116686)
		(end 54.447186 -204.116686)
		(width 0.20066)
		(layer "F.Cu")
		(net "M_A_CPU1_SB_DQ<24>")
	)
	(segment
		(start 54.447186 -204.116686)
		(end 54.708298 -204.377798)
		(width 0.20066)
		(layer "F.Cu")
		(net "M_A_CPU1_SB_DQ<24>")
	)
	(segment
		(start 55.850536 -203.68006)
		(end 56.37911 -203.68006)
		(width 0.20066)
		(layer "F.Cu")
		(net "M_A_CPU1_SB_DQ<24>")
	)
	(segment
		(start 85.152484 -222.229934)
		(end 84.938616 -222.155258)
		(width 0.088646)
		(layer "F.Cu")
		(net "M_A_CPU1_SB_DQ<24>")
	)
	(segment
		(start 59.332876 -204.116686)
		(end 60.947046 -204.116686)
		(width 0.20066)
		(layer "F.Cu")
		(net "M_A_CPU1_SB_DQ<24>")
	)
	(segment
		(start 84.69884 -222.14713)
		(end 84.254848 -222.288354)
		(width 0.088646)
		(layer "F.Cu")
		(net "M_A_CPU1_SB_DQ<24>")
	)
	(segment
		(start 68.098416 -204.265784)
		(end 68.098416 -203.708508)
		(width 0.20066)
		(layer "F.Cu")
		(net "M_A_CPU1_SB_DQ<24>")
	)
	(segment
		(start 69.520816 -204.265784)
		(end 69.520816 -203.708508)
		(width 0.20066)
		(layer "F.Cu")
		(net "M_A_CPU1_SB_DQ<24>")
	)
	(segment
		(start 67.650614 -203.507848)
		(end 67.32016 -203.838302)
		(width 0.20066)
		(layer "F.Cu")
		(net "M_A_CPU1_SB_DQ<24>")
	)
	(segment
		(start 80.89011 -214.316056)
		(end 80.89011 -214.315802)
		(width 0.1016)
		(layer "F.Cu")
		(net "M_A_CPU1_SB_DQ<24>")
	)
	(segment
		(start 68.098416 -203.708508)
		(end 67.897756 -203.507848)
		(width 0.20066)
		(layer "F.Cu")
		(net "M_A_CPU1_SB_DQ<24>")
	)
	(segment
		(start 70.432676 -203.507848)
		(end 70.232016 -203.708508)
		(width 0.20066)
		(layer "F.Cu")
		(net "M_A_CPU1_SB_DQ<24>")
	)
	(segment
		(start 81.400904 -214.82685)
		(end 80.89011 -214.316056)
		(width 0.1016)
		(layer "F.Cu")
		(net "M_A_CPU1_SB_DQ<24>")
	)
	(segment
		(start 55.647336 -204.16012)
		(end 55.647336 -203.88326)
		(width 0.20066)
		(layer "F.Cu")
		(net "M_A_CPU1_SB_DQ<24>")
	)
	(segment
		(start 84.869528 -222.141542)
		(end 84.69884 -222.14713)
		(width 0.088646)
		(layer "F.Cu")
		(net "M_A_CPU1_SB_DQ<24>")
	)
	(segment
		(start 55.429658 -204.377798)
		(end 55.647336 -204.16012)
		(width 0.20066)
		(layer "F.Cu")
		(net "M_A_CPU1_SB_DQ<24>")
	)
	(segment
		(start 70.943216 -204.265784)
		(end 70.943216 -203.708508)
		(width 0.20066)
		(layer "F.Cu")
		(net "M_A_CPU1_SB_DQ<24>")
	)
	(segment
		(start 63.951612 -203.67625)
		(end 63.26124 -203.67625)
		(width 0.20066)
		(layer "F.Cu")
		(net "M_A_CPU1_SB_DQ<24>")
	)
	(segment
		(start 55.647336 -203.88326)
		(end 55.850536 -203.68006)
		(width 0.20066)
		(layer "F.Cu")
		(net "M_A_CPU1_SB_DQ<24>")
	)
	(segment
		(start 71.453756 -204.466444)
		(end 71.143876 -204.466444)
		(width 0.20066)
		(layer "F.Cu")
		(net "M_A_CPU1_SB_DQ<24>")
	)
	(segment
		(start 58.907934 -203.691744)
		(end 59.332876 -204.116686)
		(width 0.20066)
		(layer "F.Cu")
		(net "M_A_CPU1_SB_DQ<24>")
	)
	(segment
		(start 64.140842 -203.67625)
		(end 63.951612 -203.67625)
		(width 0.101854)
		(layer "F.Cu")
		(net "M_A_CPU1_SB_DQ<24>")
	)
	(segment
		(start 81.400904 -216.006172)
		(end 81.18094 -215.786208)
		(width 0.1016)
		(layer "F.Cu")
		(net "M_A_CPU1_SB_DQ<24>")
	)
	(segment
		(start 85.415374 -222.381826)
		(end 85.29828 -222.314262)
		(width 0.088646)
		(layer "F.Cu")
		(net "M_A_CPU1_SB_DQ<24>")
	)
	(segment
		(start 85.795866 -222.48368)
		(end 85.415374 -222.381826)
		(width 0.088646)
		(layer "F.Cu")
		(net "M_A_CPU1_SB_DQ<24>")
	)
	(segment
		(start 66.238882 -203.679806)
		(end 66.161412 -203.679806)
		(width 0.20066)
		(layer "F.Cu")
		(net "M_A_CPU1_SB_DQ<24>")
	)
	(segment
		(start 81.400904 -219.773246)
		(end 81.400904 -216.006172)
		(width 0.1016)
		(layer "F.Cu")
		(net "M_A_CPU1_SB_DQ<24>")
	)
	(segment
		(start 81.18094 -215.786208)
		(end 81.18094 -215.247728)
		(width 0.1016)
		(layer "F.Cu")
		(net "M_A_CPU1_SB_DQ<24>")
	)
	(segment
		(start 69.010276 -203.507848)
		(end 68.809616 -203.708508)
		(width 0.20066)
		(layer "F.Cu")
		(net "M_A_CPU1_SB_DQ<24>")
	)
	(segment
		(start 84.938616 -222.155258)
		(end 84.869528 -222.141542)
		(width 0.088646)
		(layer "F.Cu")
		(net "M_A_CPU1_SB_DQ<24>")
	)
	(segment
		(start 84.143596 -222.305626)
		(end 83.933284 -222.305626)
		(width 0.088646)
		(layer "F.Cu")
		(net "M_A_CPU1_SB_DQ<24>")
	)
	(segment
		(start 67.32016 -203.838302)
		(end 66.618104 -203.838302)
		(width 0.20066)
		(layer "F.Cu")
		(net "M_A_CPU1_SB_DQ<24>")
	)
	(segment
		(start 56.41721 -203.691744)
		(end 58.349134 -203.691744)
		(width 0.1016)
		(layer "F.Cu")
		(net "M_A_CPU1_SB_DQ<24>")
	)
	(segment
		(start 80.872838 -214.29853)
		(end 80.872838 -214.033862)
		(width 0.1016)
		(layer "F.Cu")
		(net "M_A_CPU1_SB_DQ<24>")
	)
	(segment
		(start 62.820804 -204.116686)
		(end 60.947046 -204.116686)
		(width 0.20066)
		(layer "F.Cu")
		(net "M_A_CPU1_SB_DQ<24>")
	)
	(segment
		(start 70.232016 -203.708508)
		(end 70.232016 -204.265784)
		(width 0.20066)
		(layer "F.Cu")
		(net "M_A_CPU1_SB_DQ<24>")
	)
	(segment
		(start 66.120772 -203.691744)
		(end 64.185292 -203.691744)
		(width 0.1016)
		(layer "F.Cu")
		(net "M_A_CPU1_SB_DQ<24>")
	)
	(segment
		(start 66.618104 -203.838302)
		(end 66.57086 -203.81849)
		(width 0.20066)
		(layer "F.Cu")
		(net "M_A_CPU1_SB_DQ<24>")
	)
	(segment
		(start 69.320156 -203.507848)
		(end 69.010276 -203.507848)
		(width 0.20066)
		(layer "F.Cu")
		(net "M_A_CPU1_SB_DQ<24>")
	)
	(segment
		(start 63.26124 -203.67625)
		(end 62.820804 -204.116686)
		(width 0.20066)
		(layer "F.Cu")
		(net "M_A_CPU1_SB_DQ<24>")
	)
	(segment
		(start 69.520816 -203.708508)
		(end 69.320156 -203.507848)
		(width 0.20066)
		(layer "F.Cu")
		(net "M_A_CPU1_SB_DQ<24>")
	)
	(segment
		(start 54.708298 -204.377798)
		(end 55.429658 -204.377798)
		(width 0.20066)
		(layer "F.Cu")
		(net "M_A_CPU1_SB_DQ<24>")
	)
	(segment
		(start 58.349134 -203.691744)
		(end 58.704226 -203.691744)
		(width 0.101854)
		(layer "F.Cu")
		(net "M_A_CPU1_SB_DQ<24>")
	)
	(segment
		(start 80.89011 -214.315802)
		(end 80.872838 -214.29853)
		(width 0.1016)
		(layer "F.Cu")
		(net "M_A_CPU1_SB_DQ<24>")
	)
	(segment
		(start 70.232016 -204.265784)
		(end 70.031356 -204.466444)
		(width 0.20066)
		(layer "F.Cu")
		(net "M_A_CPU1_SB_DQ<24>")
	)
	(segment
		(start 70.943216 -203.708508)
		(end 70.742556 -203.507848)
		(width 0.20066)
		(layer "F.Cu")
		(net "M_A_CPU1_SB_DQ<24>")
	)
	(segment
		(start 68.809616 -204.265784)
		(end 68.608956 -204.466444)
		(width 0.20066)
		(layer "F.Cu")
		(net "M_A_CPU1_SB_DQ<24>")
	)
	(segment
		(start 71.143876 -204.466444)
		(end 70.943216 -204.265784)
		(width 0.20066)
		(layer "F.Cu")
		(net "M_A_CPU1_SB_DQ<24>")
	)
	(segment
		(start 68.299076 -204.466444)
		(end 68.098416 -204.265784)
		(width 0.20066)
		(layer "F.Cu")
		(net "M_A_CPU1_SB_DQ<24>")
	)
	(segment
		(start 80.872838 -212.818472)
		(end 72.130412 -204.076046)
		(width 0.20066)
		(layer "F.Cu")
		(net "M_A_CPU1_SB_DQ<24>")
	)
	(segment
		(start 68.809616 -203.708508)
		(end 68.809616 -204.265784)
		(width 0.20066)
		(layer "F.Cu")
		(net "M_A_CPU1_SB_DQ<24>")
	)
	(segment
		(start 81.400904 -215.027764)
		(end 81.400904 -214.82685)
		(width 0.1016)
		(layer "F.Cu")
		(net "M_A_CPU1_SB_DQ<24>")
	)
	(arc
		(start 84.254848 -222.288354)
		(mid 84.199886 -222.301275)
		(end 84.143596 -222.305626)
		(width 0.088646)
		(layer "F.Cu")
		(net "M_A_CPU1_SB_DQ<24>")
	)
	(segment
		(start 70.584314 -205.3336)
		(end 70.252082 -205.3336)
		(width 0.20066)
		(layer "F.Cu")
		(net "M_A_CPU1_SB_DQ<23>")
	)
	(segment
		(start 62.512448 -205.391512)
		(end 62.646814 -205.257146)
		(width 0.20066)
		(layer "F.Cu")
		(net "M_A_CPU1_SB_DQ<23>")
	)
	(segment
		(start 68.450714 -205.712568)
		(end 68.025264 -205.712568)
		(width 0.20066)
		(layer "F.Cu")
		(net "M_A_CPU1_SB_DQ<23>")
	)
	(segment
		(start 84.206842 -228.17455)
		(end 83.629246 -228.17455)
		(width 0.1016)
		(layer "F.Cu")
		(net "M_A_CPU1_SB_DQ<23>")
	)
	(segment
		(start 69.161914 -205.3336)
		(end 68.829682 -205.3336)
		(width 0.20066)
		(layer "F.Cu")
		(net "M_A_CPU1_SB_DQ<23>")
	)
	(segment
		(start 68.829682 -205.3336)
		(end 68.450714 -205.712568)
		(width 0.20066)
		(layer "F.Cu")
		(net "M_A_CPU1_SB_DQ<23>")
	)
	(segment
		(start 71.674482 -205.3336)
		(end 71.295514 -205.712568)
		(width 0.20066)
		(layer "F.Cu")
		(net "M_A_CPU1_SB_DQ<23>")
	)
	(segment
		(start 71.295514 -205.712568)
		(end 70.963282 -205.712568)
		(width 0.20066)
		(layer "F.Cu")
		(net "M_A_CPU1_SB_DQ<23>")
	)
	(segment
		(start 85.3567 -228.59619)
		(end 85.272626 -228.566726)
		(width 0.088646)
		(layer "F.Cu")
		(net "M_A_CPU1_SB_DQ<23>")
	)
	(segment
		(start 62.646814 -204.93355)
		(end 62.831218 -204.749146)
		(width 0.20066)
		(layer "F.Cu")
		(net "M_A_CPU1_SB_DQ<23>")
	)
	(segment
		(start 80.085184 -222.491554)
		(end 80.085184 -213.284562)
		(width 0.1016)
		(layer "F.Cu")
		(net "M_A_CPU1_SB_DQ<23>")
	)
	(segment
		(start 59.822842 -205.406752)
		(end 59.838082 -205.391512)
		(width 0.101854)
		(layer "F.Cu")
		(net "M_A_CPU1_SB_DQ<23>")
	)
	(segment
		(start 72.134222 -205.3336)
		(end 71.674482 -205.3336)
		(width 0.20066)
		(layer "F.Cu")
		(net "M_A_CPU1_SB_DQ<23>")
	)
	(segment
		(start 59.838082 -205.391512)
		(end 59.887612 -205.391512)
		(width 0.101854)
		(layer "F.Cu")
		(net "M_A_CPU1_SB_DQ<23>")
	)
	(segment
		(start 83.629246 -228.17455)
		(end 81.690464 -226.235768)
		(width 0.1016)
		(layer "F.Cu")
		(net "M_A_CPU1_SB_DQ<23>")
	)
	(segment
		(start 62.646814 -205.257146)
		(end 62.646814 -204.93355)
		(width 0.20066)
		(layer "F.Cu")
		(net "M_A_CPU1_SB_DQ<23>")
	)
	(segment
		(start 81.690464 -226.235768)
		(end 81.690464 -224.096834)
		(width 0.1016)
		(layer "F.Cu")
		(net "M_A_CPU1_SB_DQ<23>")
	)
	(segment
		(start 62.831218 -204.749146)
		(end 63.116206 -204.749146)
		(width 0.20066)
		(layer "F.Cu")
		(net "M_A_CPU1_SB_DQ<23>")
	)
	(segment
		(start 85.272626 -228.566726)
		(end 85.114384 -228.483414)
		(width 0.088646)
		(layer "F.Cu")
		(net "M_A_CPU1_SB_DQ<23>")
	)
	(segment
		(start 84.792312 -228.17455)
		(end 84.206842 -228.17455)
		(width 0.088646)
		(layer "F.Cu")
		(net "M_A_CPU1_SB_DQ<23>")
	)
	(segment
		(start 85.114384 -228.483414)
		(end 84.792312 -228.17455)
		(width 0.088646)
		(layer "F.Cu")
		(net "M_A_CPU1_SB_DQ<23>")
	)
	(segment
		(start 80.085184 -213.284562)
		(end 79.701136 -212.900514)
		(width 0.1016)
		(layer "F.Cu")
		(net "M_A_CPU1_SB_DQ<23>")
	)
	(segment
		(start 69.873114 -205.712568)
		(end 69.540882 -205.712568)
		(width 0.20066)
		(layer "F.Cu")
		(net "M_A_CPU1_SB_DQ<23>")
	)
	(segment
		(start 70.252082 -205.3336)
		(end 69.873114 -205.712568)
		(width 0.20066)
		(layer "F.Cu")
		(net "M_A_CPU1_SB_DQ<23>")
	)
	(segment
		(start 57.503314 -204.96657)
		(end 59.178698 -204.96657)
		(width 0.20066)
		(layer "F.Cu")
		(net "M_A_CPU1_SB_DQ<23>")
	)
	(segment
		(start 79.701136 -212.900514)
		(end 72.134222 -205.3336)
		(width 0.20066)
		(layer "F.Cu")
		(net "M_A_CPU1_SB_DQ<23>")
	)
	(segment
		(start 63.116206 -204.749146)
		(end 63.33363 -204.96657)
		(width 0.20066)
		(layer "F.Cu")
		(net "M_A_CPU1_SB_DQ<23>")
	)
	(segment
		(start 59.819286 -205.410308)
		(end 59.822842 -205.406752)
		(width 0.20066)
		(layer "F.Cu")
		(net "M_A_CPU1_SB_DQ<23>")
	)
	(segment
		(start 59.178698 -204.96657)
		(end 59.622436 -205.410308)
		(width 0.20066)
		(layer "F.Cu")
		(net "M_A_CPU1_SB_DQ<23>")
	)
	(segment
		(start 68.025264 -205.712568)
		(end 67.039236 -204.72654)
		(width 0.20066)
		(layer "F.Cu")
		(net "M_A_CPU1_SB_DQ<23>")
	)
	(segment
		(start 67.039236 -204.72654)
		(end 65.807082 -204.72654)
		(width 0.20066)
		(layer "F.Cu")
		(net "M_A_CPU1_SB_DQ<23>")
	)
	(segment
		(start 65.567052 -204.96657)
		(end 65.047114 -204.96657)
		(width 0.20066)
		(layer "F.Cu")
		(net "M_A_CPU1_SB_DQ<23>")
	)
	(segment
		(start 70.963282 -205.712568)
		(end 70.584314 -205.3336)
		(width 0.20066)
		(layer "F.Cu")
		(net "M_A_CPU1_SB_DQ<23>")
	)
	(segment
		(start 65.807082 -204.72654)
		(end 65.567052 -204.96657)
		(width 0.20066)
		(layer "F.Cu")
		(net "M_A_CPU1_SB_DQ<23>")
	)
	(segment
		(start 62.097412 -205.391512)
		(end 62.147958 -205.391512)
		(width 0.101854)
		(layer "F.Cu")
		(net "M_A_CPU1_SB_DQ<23>")
	)
	(segment
		(start 86.197186 -228.719126)
		(end 86.044786 -228.571298)
		(width 0.088646)
		(layer "F.Cu")
		(net "M_A_CPU1_SB_DQ<23>")
	)
	(segment
		(start 59.887612 -205.391512)
		(end 62.097412 -205.391512)
		(width 0.1016)
		(layer "F.Cu")
		(net "M_A_CPU1_SB_DQ<23>")
	)
	(segment
		(start 59.622436 -205.410308)
		(end 59.819286 -205.410308)
		(width 0.20066)
		(layer "F.Cu")
		(net "M_A_CPU1_SB_DQ<23>")
	)
	(segment
		(start 81.690464 -224.096834)
		(end 80.085184 -222.491554)
		(width 0.1016)
		(layer "F.Cu")
		(net "M_A_CPU1_SB_DQ<23>")
	)
	(segment
		(start 63.33363 -204.96657)
		(end 65.047114 -204.96657)
		(width 0.20066)
		(layer "F.Cu")
		(net "M_A_CPU1_SB_DQ<23>")
	)
	(segment
		(start 85.81517 -228.522022)
		(end 85.615526 -228.594666)
		(width 0.088646)
		(layer "F.Cu")
		(net "M_A_CPU1_SB_DQ<23>")
	)
	(segment
		(start 62.147958 -205.391512)
		(end 62.512448 -205.391512)
		(width 0.20066)
		(layer "F.Cu")
		(net "M_A_CPU1_SB_DQ<23>")
	)
	(segment
		(start 69.540882 -205.712568)
		(end 69.161914 -205.3336)
		(width 0.20066)
		(layer "F.Cu")
		(net "M_A_CPU1_SB_DQ<23>")
	)
	(arc
		(start 86.735666 -228.99497)
		(mid 86.444745 -228.899375)
		(end 86.197186 -228.719126)
		(width 0.088646)
		(layer "F.Cu")
		(net "M_A_CPU1_SB_DQ<23>")
	)
	(arc
		(start 85.615526 -228.594666)
		(mid 85.486244 -228.617847)
		(end 85.3567 -228.59619)
		(width 0.088646)
		(layer "F.Cu")
		(net "M_A_CPU1_SB_DQ<23>")
	)
	(arc
		(start 86.044786 -228.571298)
		(mid 85.937059 -228.513613)
		(end 85.81517 -228.522022)
		(width 0.088646)
		(layer "F.Cu")
		(net "M_A_CPU1_SB_DQ<23>")
	)
	(segment
		(start 61.863986 -207.091534)
		(end 62.140338 -207.091534)
		(width 0.101854)
		(layer "F.Cu")
		(net "M_A_CPU1_SB_DQ<22>")
	)
	(segment
		(start 78.796642 -213.805008)
		(end 71.983346 -206.991712)
		(width 0.20066)
		(layer "F.Cu")
		(net "M_A_CPU1_SB_DQ<22>")
	)
	(segment
		(start 84.932266 -229.587298)
		(end 84.862162 -229.587298)
		(width 0.088646)
		(layer "F.Cu")
		(net "M_A_CPU1_SB_DQ<22>")
	)
	(segment
		(start 59.446922 -207.108552)
		(end 59.822842 -207.108552)
		(width 0.20066)
		(layer "F.Cu")
		(net "M_A_CPU1_SB_DQ<22>")
	)
	(segment
		(start 59.822842 -207.108552)
		(end 59.845194 -207.108552)
		(width 0.101854)
		(layer "F.Cu")
		(net "M_A_CPU1_SB_DQ<22>")
	)
	(segment
		(start 83.86318 -229.271068)
		(end 83.693508 -229.101396)
		(width 0.088646)
		(layer "F.Cu")
		(net "M_A_CPU1_SB_DQ<22>")
	)
	(segment
		(start 63.79972 -206.421482)
		(end 64.04483 -206.666592)
		(width 0.20066)
		(layer "F.Cu")
		(net "M_A_CPU1_SB_DQ<22>")
	)
	(segment
		(start 84.80044 -229.64902)
		(end 84.296758 -229.64902)
		(width 0.088646)
		(layer "F.Cu")
		(net "M_A_CPU1_SB_DQ<22>")
	)
	(segment
		(start 62.75832 -206.610712)
		(end 62.94755 -206.421482)
		(width 0.20066)
		(layer "F.Cu")
		(net "M_A_CPU1_SB_DQ<22>")
	)
	(segment
		(start 59.862212 -207.091534)
		(end 61.863986 -207.091534)
		(width 0.1016)
		(layer "F.Cu")
		(net "M_A_CPU1_SB_DQ<22>")
	)
	(segment
		(start 79.475584 -214.48395)
		(end 78.796642 -213.805008)
		(width 0.1016)
		(layer "F.Cu")
		(net "M_A_CPU1_SB_DQ<22>")
	)
	(segment
		(start 71.507096 -206.991712)
		(end 71.111364 -207.387444)
		(width 0.20066)
		(layer "F.Cu")
		(net "M_A_CPU1_SB_DQ<22>")
	)
	(segment
		(start 62.147958 -207.099154)
		(end 62.558676 -207.099154)
		(width 0.20066)
		(layer "F.Cu")
		(net "M_A_CPU1_SB_DQ<22>")
	)
	(segment
		(start 83.693508 -229.101396)
		(end 81.080864 -226.488752)
		(width 0.1016)
		(layer "F.Cu")
		(net "M_A_CPU1_SB_DQ<22>")
	)
	(segment
		(start 59.845194 -207.108552)
		(end 59.862212 -207.091534)
		(width 0.101854)
		(layer "F.Cu")
		(net "M_A_CPU1_SB_DQ<22>")
	)
	(segment
		(start 69.373496 -207.387444)
		(end 68.977764 -206.991712)
		(width 0.20066)
		(layer "F.Cu")
		(net "M_A_CPU1_SB_DQ<22>")
	)
	(segment
		(start 68.977764 -206.991712)
		(end 68.662296 -206.991712)
		(width 0.20066)
		(layer "F.Cu")
		(net "M_A_CPU1_SB_DQ<22>")
	)
	(segment
		(start 57.503314 -206.666592)
		(end 59.004962 -206.666592)
		(width 0.20066)
		(layer "F.Cu")
		(net "M_A_CPU1_SB_DQ<22>")
	)
	(segment
		(start 71.111364 -207.387444)
		(end 70.795896 -207.387444)
		(width 0.20066)
		(layer "F.Cu")
		(net "M_A_CPU1_SB_DQ<22>")
	)
	(segment
		(start 66.78295 -206.36865)
		(end 66.350134 -206.36865)
		(width 0.20066)
		(layer "F.Cu")
		(net "M_A_CPU1_SB_DQ<22>")
	)
	(segment
		(start 62.558676 -207.099154)
		(end 62.75832 -206.89951)
		(width 0.20066)
		(layer "F.Cu")
		(net "M_A_CPU1_SB_DQ<22>")
	)
	(segment
		(start 59.004962 -206.666592)
		(end 59.446922 -207.108552)
		(width 0.20066)
		(layer "F.Cu")
		(net "M_A_CPU1_SB_DQ<22>")
	)
	(segment
		(start 68.266564 -207.387444)
		(end 67.801744 -207.387444)
		(width 0.20066)
		(layer "F.Cu")
		(net "M_A_CPU1_SB_DQ<22>")
	)
	(segment
		(start 66.052192 -206.666592)
		(end 65.047114 -206.666592)
		(width 0.20066)
		(layer "F.Cu")
		(net "M_A_CPU1_SB_DQ<22>")
	)
	(segment
		(start 64.04483 -206.666592)
		(end 65.047114 -206.666592)
		(width 0.20066)
		(layer "F.Cu")
		(net "M_A_CPU1_SB_DQ<22>")
	)
	(segment
		(start 62.94755 -206.421482)
		(end 63.79972 -206.421482)
		(width 0.20066)
		(layer "F.Cu")
		(net "M_A_CPU1_SB_DQ<22>")
	)
	(segment
		(start 70.795896 -207.387444)
		(end 70.400164 -206.991712)
		(width 0.20066)
		(layer "F.Cu")
		(net "M_A_CPU1_SB_DQ<22>")
	)
	(segment
		(start 70.400164 -206.991712)
		(end 70.084696 -206.991712)
		(width 0.20066)
		(layer "F.Cu")
		(net "M_A_CPU1_SB_DQ<22>")
	)
	(segment
		(start 62.75832 -206.89951)
		(end 62.75832 -206.610712)
		(width 0.20066)
		(layer "F.Cu")
		(net "M_A_CPU1_SB_DQ<22>")
	)
	(segment
		(start 68.662296 -206.991712)
		(end 68.266564 -207.387444)
		(width 0.20066)
		(layer "F.Cu")
		(net "M_A_CPU1_SB_DQ<22>")
	)
	(segment
		(start 83.86318 -229.366826)
		(end 83.86318 -229.271068)
		(width 0.088646)
		(layer "F.Cu")
		(net "M_A_CPU1_SB_DQ<22>")
	)
	(segment
		(start 70.084696 -206.991712)
		(end 69.688964 -207.387444)
		(width 0.20066)
		(layer "F.Cu")
		(net "M_A_CPU1_SB_DQ<22>")
	)
	(segment
		(start 69.688964 -207.387444)
		(end 69.373496 -207.387444)
		(width 0.20066)
		(layer "F.Cu")
		(net "M_A_CPU1_SB_DQ<22>")
	)
	(segment
		(start 66.350134 -206.36865)
		(end 66.052192 -206.666592)
		(width 0.20066)
		(layer "F.Cu")
		(net "M_A_CPU1_SB_DQ<22>")
	)
	(segment
		(start 79.475584 -222.744538)
		(end 79.475584 -214.48395)
		(width 0.1016)
		(layer "F.Cu")
		(net "M_A_CPU1_SB_DQ<22>")
	)
	(segment
		(start 84.862162 -229.587298)
		(end 84.80044 -229.64902)
		(width 0.088646)
		(layer "F.Cu")
		(net "M_A_CPU1_SB_DQ<22>")
	)
	(segment
		(start 85.246972 -229.345236)
		(end 85.225128 -229.356666)
		(width 0.088646)
		(layer "F.Cu")
		(net "M_A_CPU1_SB_DQ<22>")
	)
	(segment
		(start 84.296758 -229.64902)
		(end 84.03844 -229.542086)
		(width 0.088646)
		(layer "F.Cu")
		(net "M_A_CPU1_SB_DQ<22>")
	)
	(segment
		(start 81.080864 -224.349818)
		(end 79.475584 -222.744538)
		(width 0.1016)
		(layer "F.Cu")
		(net "M_A_CPU1_SB_DQ<22>")
	)
	(segment
		(start 84.03844 -229.542086)
		(end 83.86318 -229.366826)
		(width 0.088646)
		(layer "F.Cu")
		(net "M_A_CPU1_SB_DQ<22>")
	)
	(segment
		(start 71.983346 -206.991712)
		(end 71.507096 -206.991712)
		(width 0.20066)
		(layer "F.Cu")
		(net "M_A_CPU1_SB_DQ<22>")
	)
	(segment
		(start 67.801744 -207.387444)
		(end 66.78295 -206.36865)
		(width 0.20066)
		(layer "F.Cu")
		(net "M_A_CPU1_SB_DQ<22>")
	)
	(segment
		(start 81.080864 -226.488752)
		(end 81.080864 -224.349818)
		(width 0.1016)
		(layer "F.Cu")
		(net "M_A_CPU1_SB_DQ<22>")
	)
	(segment
		(start 87.205312 -229.808786)
		(end 86.500716 -229.401878)
		(width 0.088646)
		(layer "F.Cu")
		(net "M_A_CPU1_SB_DQ<22>")
	)
	(segment
		(start 62.140338 -207.091534)
		(end 62.147958 -207.099154)
		(width 0.101854)
		(layer "F.Cu")
		(net "M_A_CPU1_SB_DQ<22>")
	)
	(segment
		(start 85.225128 -229.356666)
		(end 85.03793 -229.543864)
		(width 0.088646)
		(layer "F.Cu")
		(net "M_A_CPU1_SB_DQ<22>")
	)
	(arc
		(start 86.030816 -229.401878)
		(mid 85.795866 -229.464838)
		(end 85.560916 -229.401878)
		(width 0.088646)
		(layer "F.Cu")
		(net "M_A_CPU1_SB_DQ<22>")
	)
	(arc
		(start 86.500716 -229.401878)
		(mid 86.265766 -229.338918)
		(end 86.030816 -229.401878)
		(width 0.088646)
		(layer "F.Cu")
		(net "M_A_CPU1_SB_DQ<22>")
	)
	(arc
		(start 85.03793 -229.543864)
		(mid 84.989394 -229.576043)
		(end 84.932266 -229.587298)
		(width 0.088646)
		(layer "F.Cu")
		(net "M_A_CPU1_SB_DQ<22>")
	)
	(arc
		(start 85.560916 -229.401878)
		(mid 85.408895 -229.346128)
		(end 85.246972 -229.345236)
		(width 0.088646)
		(layer "F.Cu")
		(net "M_A_CPU1_SB_DQ<22>")
	)
	(segment
		(start 58.349134 -205.391766)
		(end 58.704226 -205.391766)
		(width 0.101854)
		(layer "F.Cu")
		(net "M_A_CPU1_SB_DQ<21>")
	)
	(segment
		(start 55.433214 -206.07782)
		(end 55.647336 -205.863698)
		(width 0.20066)
		(layer "F.Cu")
		(net "M_A_CPU1_SB_DQ<21>")
	)
	(segment
		(start 54.447186 -205.816708)
		(end 54.708298 -206.07782)
		(width 0.20066)
		(layer "F.Cu")
		(net "M_A_CPU1_SB_DQ<21>")
	)
	(segment
		(start 58.704226 -205.391766)
		(end 58.907934 -205.391766)
		(width 0.20066)
		(layer "F.Cu")
		(net "M_A_CPU1_SB_DQ<21>")
	)
	(segment
		(start 67.69608 -206.35214)
		(end 66.710052 -205.366112)
		(width 0.20066)
		(layer "F.Cu")
		(net "M_A_CPU1_SB_DQ<21>")
	)
	(segment
		(start 59.332876 -205.816708)
		(end 60.947046 -205.816708)
		(width 0.20066)
		(layer "F.Cu")
		(net "M_A_CPU1_SB_DQ<21>")
	)
	(segment
		(start 56.37911 -205.380082)
		(end 56.41721 -205.391766)
		(width 0.1016)
		(layer "F.Cu")
		(net "M_A_CPU1_SB_DQ<21>")
	)
	(segment
		(start 79.248762 -213.352634)
		(end 72.248268 -206.35214)
		(width 0.20066)
		(layer "F.Cu")
		(net "M_A_CPU1_SB_DQ<21>")
	)
	(segment
		(start 61.996574 -205.877922)
		(end 61.93536 -205.816708)
		(width 0.20066)
		(layer "F.Cu")
		(net "M_A_CPU1_SB_DQ<21>")
	)
	(segment
		(start 66.212212 -205.366112)
		(end 66.026284 -205.366112)
		(width 0.101854)
		(layer "F.Cu")
		(net "M_A_CPU1_SB_DQ<21>")
	)
	(segment
		(start 79.780384 -222.618046)
		(end 79.780384 -213.884256)
		(width 0.1016)
		(layer "F.Cu")
		(net "M_A_CPU1_SB_DQ<21>")
	)
	(segment
		(start 55.850536 -205.380082)
		(end 56.37911 -205.380082)
		(width 0.20066)
		(layer "F.Cu")
		(net "M_A_CPU1_SB_DQ<21>")
	)
	(segment
		(start 83.512914 -228.48951)
		(end 81.385664 -226.36226)
		(width 0.1016)
		(layer "F.Cu")
		(net "M_A_CPU1_SB_DQ<21>")
	)
	(segment
		(start 58.907934 -205.391766)
		(end 59.332876 -205.816708)
		(width 0.20066)
		(layer "F.Cu")
		(net "M_A_CPU1_SB_DQ<21>")
	)
	(segment
		(start 84.954364 -228.634036)
		(end 84.675472 -228.48951)
		(width 0.088646)
		(layer "F.Cu")
		(net "M_A_CPU1_SB_DQ<21>")
	)
	(segment
		(start 63.260986 -205.376526)
		(end 63.178182 -205.45933)
		(width 0.20066)
		(layer "F.Cu")
		(net "M_A_CPU1_SB_DQ<21>")
	)
	(segment
		(start 63.036704 -205.877922)
		(end 61.996574 -205.877922)
		(width 0.20066)
		(layer "F.Cu")
		(net "M_A_CPU1_SB_DQ<21>")
	)
	(segment
		(start 81.385664 -226.36226)
		(end 81.385664 -224.223326)
		(width 0.1016)
		(layer "F.Cu")
		(net "M_A_CPU1_SB_DQ<21>")
	)
	(segment
		(start 61.93536 -205.816708)
		(end 60.947046 -205.816708)
		(width 0.20066)
		(layer "F.Cu")
		(net "M_A_CPU1_SB_DQ<21>")
	)
	(segment
		(start 66.026284 -205.366112)
		(end 66.000884 -205.391512)
		(width 0.101854)
		(layer "F.Cu")
		(net "M_A_CPU1_SB_DQ<21>")
	)
	(segment
		(start 56.41721 -205.391766)
		(end 58.349134 -205.391766)
		(width 0.1016)
		(layer "F.Cu")
		(net "M_A_CPU1_SB_DQ<21>")
	)
	(segment
		(start 85.795866 -228.99497)
		(end 85.256878 -228.783642)
		(width 0.088646)
		(layer "F.Cu")
		(net "M_A_CPU1_SB_DQ<21>")
	)
	(segment
		(start 55.647336 -205.583282)
		(end 55.850536 -205.380082)
		(width 0.20066)
		(layer "F.Cu")
		(net "M_A_CPU1_SB_DQ<21>")
	)
	(segment
		(start 55.647336 -205.863698)
		(end 55.647336 -205.583282)
		(width 0.20066)
		(layer "F.Cu")
		(net "M_A_CPU1_SB_DQ<21>")
	)
	(segment
		(start 63.178182 -205.45933)
		(end 63.178182 -205.736444)
		(width 0.20066)
		(layer "F.Cu")
		(net "M_A_CPU1_SB_DQ<21>")
	)
	(segment
		(start 64.142366 -205.376526)
		(end 63.900812 -205.376526)
		(width 0.101854)
		(layer "F.Cu")
		(net "M_A_CPU1_SB_DQ<21>")
	)
	(segment
		(start 66.000884 -205.391512)
		(end 64.185292 -205.391512)
		(width 0.1016)
		(layer "F.Cu")
		(net "M_A_CPU1_SB_DQ<21>")
	)
	(segment
		(start 84.675472 -228.48951)
		(end 84.206842 -228.48951)
		(width 0.088646)
		(layer "F.Cu")
		(net "M_A_CPU1_SB_DQ<21>")
	)
	(segment
		(start 85.256878 -228.783642)
		(end 84.954364 -228.634036)
		(width 0.088646)
		(layer "F.Cu")
		(net "M_A_CPU1_SB_DQ<21>")
	)
	(segment
		(start 64.185292 -205.391512)
		(end 64.142366 -205.376526)
		(width 0.1016)
		(layer "F.Cu")
		(net "M_A_CPU1_SB_DQ<21>")
	)
	(segment
		(start 79.780384 -213.884256)
		(end 79.248762 -213.352634)
		(width 0.1016)
		(layer "F.Cu")
		(net "M_A_CPU1_SB_DQ<21>")
	)
	(segment
		(start 53.403246 -205.816708)
		(end 54.447186 -205.816708)
		(width 0.20066)
		(layer "F.Cu")
		(net "M_A_CPU1_SB_DQ<21>")
	)
	(segment
		(start 63.900812 -205.376526)
		(end 63.260986 -205.376526)
		(width 0.20066)
		(layer "F.Cu")
		(net "M_A_CPU1_SB_DQ<21>")
	)
	(segment
		(start 72.248268 -206.35214)
		(end 67.69608 -206.35214)
		(width 0.20066)
		(layer "F.Cu")
		(net "M_A_CPU1_SB_DQ<21>")
	)
	(segment
		(start 54.708298 -206.07782)
		(end 55.433214 -206.07782)
		(width 0.20066)
		(layer "F.Cu")
		(net "M_A_CPU1_SB_DQ<21>")
	)
	(segment
		(start 63.178182 -205.736444)
		(end 63.036704 -205.877922)
		(width 0.20066)
		(layer "F.Cu")
		(net "M_A_CPU1_SB_DQ<21>")
	)
	(segment
		(start 66.710052 -205.366112)
		(end 66.212212 -205.366112)
		(width 0.20066)
		(layer "F.Cu")
		(net "M_A_CPU1_SB_DQ<21>")
	)
	(segment
		(start 81.385664 -224.223326)
		(end 79.780384 -222.618046)
		(width 0.1016)
		(layer "F.Cu")
		(net "M_A_CPU1_SB_DQ<21>")
	)
	(segment
		(start 84.206842 -228.48951)
		(end 83.512914 -228.48951)
		(width 0.1016)
		(layer "F.Cu")
		(net "M_A_CPU1_SB_DQ<21>")
	)
	(segment
		(start 85.284818 -229.84968)
		(end 84.260436 -229.84968)
		(width 0.088646)
		(layer "F.Cu")
		(net "M_A_CPU1_SB_DQ<20>")
	)
	(segment
		(start 83.477608 -229.317042)
		(end 80.776064 -226.615498)
		(width 0.1016)
		(layer "F.Cu")
		(net "M_A_CPU1_SB_DQ<20>")
	)
	(segment
		(start 80.776064 -226.615498)
		(end 80.776064 -224.47631)
		(width 0.1016)
		(layer "F.Cu")
		(net "M_A_CPU1_SB_DQ<20>")
	)
	(segment
		(start 65.993518 -207.054196)
		(end 65.903348 -207.091534)
		(width 0.1016)
		(layer "F.Cu")
		(net "M_A_CPU1_SB_DQ<20>")
	)
	(segment
		(start 84.260436 -229.84968)
		(end 83.833208 -229.672642)
		(width 0.088646)
		(layer "F.Cu")
		(net "M_A_CPU1_SB_DQ<20>")
	)
	(segment
		(start 63.019178 -207.51673)
		(end 60.947046 -207.51673)
		(width 0.20066)
		(layer "F.Cu")
		(net "M_A_CPU1_SB_DQ<20>")
	)
	(segment
		(start 63.900812 -207.049878)
		(end 63.48603 -207.049878)
		(width 0.20066)
		(layer "F.Cu")
		(net "M_A_CPU1_SB_DQ<20>")
	)
	(segment
		(start 85.325712 -229.808786)
		(end 85.284818 -229.84968)
		(width 0.088646)
		(layer "F.Cu")
		(net "M_A_CPU1_SB_DQ<20>")
	)
	(segment
		(start 54.713378 -207.51673)
		(end 54.966362 -207.769714)
		(width 0.20066)
		(layer "F.Cu")
		(net "M_A_CPU1_SB_DQ<20>")
	)
	(segment
		(start 79.170784 -222.87103)
		(end 79.170784 -215.083898)
		(width 0.1016)
		(layer "F.Cu")
		(net "M_A_CPU1_SB_DQ<20>")
	)
	(segment
		(start 65.903348 -207.091534)
		(end 64.185292 -207.091534)
		(width 0.1016)
		(layer "F.Cu")
		(net "M_A_CPU1_SB_DQ<20>")
	)
	(segment
		(start 66.237612 -207.054196)
		(end 65.993518 -207.054196)
		(width 0.1016)
		(layer "F.Cu")
		(net "M_A_CPU1_SB_DQ<20>")
	)
	(segment
		(start 55.34787 -207.769714)
		(end 55.583328 -207.534256)
		(width 0.20066)
		(layer "F.Cu")
		(net "M_A_CPU1_SB_DQ<20>")
	)
	(segment
		(start 72.113902 -208.027016)
		(end 67.501516 -208.027016)
		(width 0.20066)
		(layer "F.Cu")
		(net "M_A_CPU1_SB_DQ<20>")
	)
	(segment
		(start 58.349134 -207.091534)
		(end 58.704226 -207.091534)
		(width 0.101854)
		(layer "F.Cu")
		(net "M_A_CPU1_SB_DQ<20>")
	)
	(segment
		(start 79.170784 -215.083898)
		(end 78.55839 -214.471504)
		(width 0.1016)
		(layer "F.Cu")
		(net "M_A_CPU1_SB_DQ<20>")
	)
	(segment
		(start 54.966362 -207.769714)
		(end 55.34787 -207.769714)
		(width 0.20066)
		(layer "F.Cu")
		(net "M_A_CPU1_SB_DQ<20>")
	)
	(segment
		(start 83.833208 -229.672642)
		(end 83.477608 -229.317042)
		(width 0.088646)
		(layer "F.Cu")
		(net "M_A_CPU1_SB_DQ<20>")
	)
	(segment
		(start 63.48603 -207.049878)
		(end 63.019178 -207.51673)
		(width 0.20066)
		(layer "F.Cu")
		(net "M_A_CPU1_SB_DQ<20>")
	)
	(segment
		(start 55.746142 -207.083406)
		(end 56.37911 -207.083406)
		(width 0.20066)
		(layer "F.Cu")
		(net "M_A_CPU1_SB_DQ<20>")
	)
	(segment
		(start 66.528696 -207.054196)
		(end 66.237612 -207.054196)
		(width 0.20066)
		(layer "F.Cu")
		(net "M_A_CPU1_SB_DQ<20>")
	)
	(segment
		(start 55.583328 -207.24622)
		(end 55.746142 -207.083406)
		(width 0.20066)
		(layer "F.Cu")
		(net "M_A_CPU1_SB_DQ<20>")
	)
	(segment
		(start 78.55839 -214.471504)
		(end 72.113902 -208.027016)
		(width 0.20066)
		(layer "F.Cu")
		(net "M_A_CPU1_SB_DQ<20>")
	)
	(segment
		(start 56.387238 -207.091534)
		(end 58.349134 -207.091534)
		(width 0.1016)
		(layer "F.Cu")
		(net "M_A_CPU1_SB_DQ<20>")
	)
	(segment
		(start 59.253628 -207.51673)
		(end 60.947046 -207.51673)
		(width 0.20066)
		(layer "F.Cu")
		(net "M_A_CPU1_SB_DQ<20>")
	)
	(segment
		(start 58.704226 -207.091534)
		(end 58.828432 -207.091534)
		(width 0.20066)
		(layer "F.Cu")
		(net "M_A_CPU1_SB_DQ<20>")
	)
	(segment
		(start 56.37911 -207.083406)
		(end 56.387238 -207.091534)
		(width 0.1016)
		(layer "F.Cu")
		(net "M_A_CPU1_SB_DQ<20>")
	)
	(segment
		(start 64.185292 -207.091534)
		(end 64.064642 -207.049878)
		(width 0.1016)
		(layer "F.Cu")
		(net "M_A_CPU1_SB_DQ<20>")
	)
	(segment
		(start 55.583328 -207.534256)
		(end 55.583328 -207.24622)
		(width 0.20066)
		(layer "F.Cu")
		(net "M_A_CPU1_SB_DQ<20>")
	)
	(segment
		(start 64.064642 -207.049878)
		(end 63.900812 -207.049878)
		(width 0.1016)
		(layer "F.Cu")
		(net "M_A_CPU1_SB_DQ<20>")
	)
	(segment
		(start 67.501516 -208.027016)
		(end 66.528696 -207.054196)
		(width 0.20066)
		(layer "F.Cu")
		(net "M_A_CPU1_SB_DQ<20>")
	)
	(segment
		(start 80.776064 -224.47631)
		(end 79.170784 -222.87103)
		(width 0.1016)
		(layer "F.Cu")
		(net "M_A_CPU1_SB_DQ<20>")
	)
	(segment
		(start 58.828432 -207.091534)
		(end 59.253628 -207.51673)
		(width 0.20066)
		(layer "F.Cu")
		(net "M_A_CPU1_SB_DQ<20>")
	)
	(segment
		(start 53.403246 -207.51673)
		(end 54.713378 -207.51673)
		(width 0.20066)
		(layer "F.Cu")
		(net "M_A_CPU1_SB_DQ<20>")
	)
	(segment
		(start 54.713378 -230.466646)
		(end 53.403246 -230.466646)
		(width 0.20066)
		(layer "F.Cu")
		(net "M_A_CPU1_SB_DQ<1>")
	)
	(segment
		(start 55.583328 -230.196136)
		(end 55.583328 -230.484172)
		(width 0.20066)
		(layer "F.Cu")
		(net "M_A_CPU1_SB_DQ<1>")
	)
	(segment
		(start 59.332876 -230.466646)
		(end 58.893202 -230.026972)
		(width 0.20066)
		(layer "F.Cu")
		(net "M_A_CPU1_SB_DQ<1>")
	)
	(segment
		(start 55.34914 -230.71836)
		(end 54.965092 -230.71836)
		(width 0.20066)
		(layer "F.Cu")
		(net "M_A_CPU1_SB_DQ<1>")
	)
	(segment
		(start 55.583328 -230.484172)
		(end 55.34914 -230.71836)
		(width 0.20066)
		(layer "F.Cu")
		(net "M_A_CPU1_SB_DQ<1>")
	)
	(segment
		(start 62.051946 -230.466646)
		(end 60.947046 -230.466646)
		(width 0.20066)
		(layer "F.Cu")
		(net "M_A_CPU1_SB_DQ<1>")
	)
	(segment
		(start 88.615266 -238.761524)
		(end 88.615012 -238.76127)
		(width 0.20066)
		(layer "F.Cu")
		(net "M_A_CPU1_SB_DQ<1>")
	)
	(segment
		(start 60.947046 -230.466646)
		(end 59.332876 -230.466646)
		(width 0.20066)
		(layer "F.Cu")
		(net "M_A_CPU1_SB_DQ<1>")
	)
	(segment
		(start 58.349134 -230.041704)
		(end 56.610758 -230.041704)
		(width 0.1016)
		(layer "F.Cu")
		(net "M_A_CPU1_SB_DQ<1>")
	)
	(segment
		(start 58.704226 -230.026972)
		(end 58.400442 -230.026972)
		(width 0.101854)
		(layer "F.Cu")
		(net "M_A_CPU1_SB_DQ<1>")
	)
	(segment
		(start 56.610758 -230.041704)
		(end 56.475376 -230.000302)
		(width 0.1016)
		(layer "F.Cu")
		(net "M_A_CPU1_SB_DQ<1>")
	)
	(segment
		(start 58.400442 -230.026972)
		(end 58.349134 -230.041704)
		(width 0.1016)
		(layer "F.Cu")
		(net "M_A_CPU1_SB_DQ<1>")
	)
	(segment
		(start 55.779162 -230.000302)
		(end 55.583328 -230.196136)
		(width 0.20066)
		(layer "F.Cu")
		(net "M_A_CPU1_SB_DQ<1>")
	)
	(segment
		(start 58.893202 -230.026972)
		(end 58.704226 -230.026972)
		(width 0.20066)
		(layer "F.Cu")
		(net "M_A_CPU1_SB_DQ<1>")
	)
	(segment
		(start 56.407812 -230.000302)
		(end 56.37911 -230.000302)
		(width 0.101854)
		(layer "F.Cu")
		(net "M_A_CPU1_SB_DQ<1>")
	)
	(segment
		(start 54.965092 -230.71836)
		(end 54.713378 -230.466646)
		(width 0.20066)
		(layer "F.Cu")
		(net "M_A_CPU1_SB_DQ<1>")
	)
	(segment
		(start 56.37911 -230.000302)
		(end 55.779162 -230.000302)
		(width 0.20066)
		(layer "F.Cu")
		(net "M_A_CPU1_SB_DQ<1>")
	)
	(segment
		(start 56.475376 -230.000302)
		(end 56.407812 -230.000302)
		(width 0.1016)
		(layer "F.Cu")
		(net "M_A_CPU1_SB_DQ<1>")
	)
	(segment
		(start 88.615012 -238.76127)
		(end 88.615012 -238.225584)
		(width 0.20066)
		(layer "F.Cu")
		(net "M_A_CPU1_SB_DQ<1>")
	)
	(segment
		(start 66.352166 -230.041704)
		(end 65.816988 -230.041704)
		(width 0.18288)
		(layer "In2.Cu")
		(net "M_A_CPU1_SB_DQ<1>")
	)
	(segment
		(start 62.34049 -230.466646)
		(end 62.051946 -230.466646)
		(width 0.18288)
		(layer "In2.Cu")
		(net "M_A_CPU1_SB_DQ<1>")
	)
	(segment
		(start 83.32089 -238.58982)
		(end 82.759296 -238.58982)
		(width 0.088646)
		(layer "In2.Cu")
		(net "M_A_CPU1_SB_DQ<1>")
	)
	(segment
		(start 83.916266 -238.790734)
		(end 83.521804 -238.790734)
		(width 0.088646)
		(layer "In2.Cu")
		(net "M_A_CPU1_SB_DQ<1>")
	)
	(segment
		(start 87.986362 -238.69904)
		(end 87.958168 -238.715042)
		(width 0.088646)
		(layer "In2.Cu")
		(net "M_A_CPU1_SB_DQ<1>")
	)
	(segment
		(start 65.255394 -230.603298)
		(end 64.755268 -230.603298)
		(width 0.18288)
		(layer "In2.Cu")
		(net "M_A_CPU1_SB_DQ<1>")
	)
	(segment
		(start 63.463932 -229.311962)
		(end 62.726824 -229.311962)
		(width 0.18288)
		(layer "In2.Cu")
		(net "M_A_CPU1_SB_DQ<1>")
	)
	(segment
		(start 78.733142 -238.58982)
		(end 71.449692 -231.30637)
		(width 0.18288)
		(layer "In2.Cu")
		(net "M_A_CPU1_SB_DQ<1>")
	)
	(segment
		(start 66.702178 -230.391716)
		(end 66.352166 -230.041704)
		(width 0.18288)
		(layer "In2.Cu")
		(net "M_A_CPU1_SB_DQ<1>")
	)
	(segment
		(start 88.615012 -238.225584)
		(end 87.986362 -238.69904)
		(width 0.088646)
		(layer "In2.Cu")
		(net "M_A_CPU1_SB_DQ<1>")
	)
	(segment
		(start 62.726824 -229.311962)
		(end 62.533784 -229.505002)
		(width 0.18288)
		(layer "In2.Cu")
		(net "M_A_CPU1_SB_DQ<1>")
	)
	(segment
		(start 71.449692 -231.30637)
		(end 68.066666 -231.30637)
		(width 0.18288)
		(layer "In2.Cu")
		(net "M_A_CPU1_SB_DQ<1>")
	)
	(segment
		(start 62.533784 -229.505002)
		(end 62.533784 -230.273352)
		(width 0.18288)
		(layer "In2.Cu")
		(net "M_A_CPU1_SB_DQ<1>")
	)
	(segment
		(start 68.066666 -231.30637)
		(end 67.65417 -231.135428)
		(width 0.18288)
		(layer "In2.Cu")
		(net "M_A_CPU1_SB_DQ<1>")
	)
	(segment
		(start 64.755268 -230.603298)
		(end 63.463932 -229.311962)
		(width 0.18288)
		(layer "In2.Cu")
		(net "M_A_CPU1_SB_DQ<1>")
	)
	(segment
		(start 62.533784 -230.273352)
		(end 62.34049 -230.466646)
		(width 0.18288)
		(layer "In2.Cu")
		(net "M_A_CPU1_SB_DQ<1>")
	)
	(segment
		(start 66.910458 -230.391716)
		(end 66.702178 -230.391716)
		(width 0.18288)
		(layer "In2.Cu")
		(net "M_A_CPU1_SB_DQ<1>")
	)
	(segment
		(start 65.816988 -230.041704)
		(end 65.255394 -230.603298)
		(width 0.18288)
		(layer "In2.Cu")
		(net "M_A_CPU1_SB_DQ<1>")
	)
	(segment
		(start 83.521804 -238.790734)
		(end 83.32089 -238.58982)
		(width 0.088646)
		(layer "In2.Cu")
		(net "M_A_CPU1_SB_DQ<1>")
	)
	(segment
		(start 67.65417 -231.135428)
		(end 66.910458 -230.391716)
		(width 0.18288)
		(layer "In2.Cu")
		(net "M_A_CPU1_SB_DQ<1>")
	)
	(segment
		(start 82.759296 -238.58982)
		(end 78.733142 -238.58982)
		(width 0.18288)
		(layer "In2.Cu")
		(net "M_A_CPU1_SB_DQ<1>")
	)
	(arc
		(start 87.018368 -238.715042)
		(mid 86.735666 -238.790818)
		(end 86.452964 -238.715042)
		(width 0.088646)
		(layer "In2.Cu")
		(net "M_A_CPU1_SB_DQ<1>")
	)
	(arc
		(start 87.392764 -238.715042)
		(mid 87.205566 -238.664899)
		(end 87.018368 -238.715042)
		(width 0.088646)
		(layer "In2.Cu")
		(net "M_A_CPU1_SB_DQ<1>")
	)
	(arc
		(start 87.958168 -238.715042)
		(mid 87.675466 -238.790818)
		(end 87.392764 -238.715042)
		(width 0.088646)
		(layer "In2.Cu")
		(net "M_A_CPU1_SB_DQ<1>")
	)
	(arc
		(start 86.078568 -238.715042)
		(mid 85.795866 -238.790818)
		(end 85.513164 -238.715042)
		(width 0.088646)
		(layer "In2.Cu")
		(net "M_A_CPU1_SB_DQ<1>")
	)
	(arc
		(start 85.138768 -238.715042)
		(mid 84.856066 -238.790818)
		(end 84.573364 -238.715042)
		(width 0.088646)
		(layer "In2.Cu")
		(net "M_A_CPU1_SB_DQ<1>")
	)
	(arc
		(start 84.198968 -238.715042)
		(mid 84.062599 -238.771484)
		(end 83.916266 -238.790734)
		(width 0.088646)
		(layer "In2.Cu")
		(net "M_A_CPU1_SB_DQ<1>")
	)
	(arc
		(start 84.573364 -238.715042)
		(mid 84.386166 -238.664899)
		(end 84.198968 -238.715042)
		(width 0.088646)
		(layer "In2.Cu")
		(net "M_A_CPU1_SB_DQ<1>")
	)
	(arc
		(start 85.513164 -238.715042)
		(mid 85.325966 -238.664899)
		(end 85.138768 -238.715042)
		(width 0.088646)
		(layer "In2.Cu")
		(net "M_A_CPU1_SB_DQ<1>")
	)
	(arc
		(start 86.452964 -238.715042)
		(mid 86.265766 -238.664899)
		(end 86.078568 -238.715042)
		(width 0.088646)
		(layer "In2.Cu")
		(net "M_A_CPU1_SB_DQ<1>")
	)
	(segment
		(start 62.147958 -211.341716)
		(end 62.426088 -211.341716)
		(width 0.20066)
		(layer "F.Cu")
		(net "M_A_CPU1_SB_DQ<19>")
	)
	(segment
		(start 77.646784 -217.553794)
		(end 77.078078 -216.985088)
		(width 0.1016)
		(layer "F.Cu")
		(net "M_A_CPU1_SB_DQ<19>")
	)
	(segment
		(start 85.718904 -231.207564)
		(end 85.544406 -231.033066)
		(width 0.088646)
		(layer "F.Cu")
		(net "M_A_CPU1_SB_DQ<19>")
	)
	(segment
		(start 79.252064 -227.247958)
		(end 79.252064 -225.108262)
		(width 0.1016)
		(layer "F.Cu")
		(net "M_A_CPU1_SB_DQ<19>")
	)
	(segment
		(start 70.603872 -212.363304)
		(end 70.603872 -212.079332)
		(width 0.20066)
		(layer "F.Cu")
		(net "M_A_CPU1_SB_DQ<19>")
	)
	(segment
		(start 72.032622 -211.940394)
		(end 71.74865 -211.940394)
		(width 0.20066)
		(layer "F.Cu")
		(net "M_A_CPU1_SB_DQ<19>")
	)
	(segment
		(start 83.521042 -231.293416)
		(end 83.297522 -231.293416)
		(width 0.1016)
		(layer "F.Cu")
		(net "M_A_CPU1_SB_DQ<19>")
	)
	(segment
		(start 62.541404 -211.2264)
		(end 62.541404 -210.888834)
		(width 0.20066)
		(layer "F.Cu")
		(net "M_A_CPU1_SB_DQ<19>")
	)
	(segment
		(start 79.252064 -225.108262)
		(end 77.646784 -223.502982)
		(width 0.1016)
		(layer "F.Cu")
		(net "M_A_CPU1_SB_DQ<19>")
	)
	(segment
		(start 71.24573 -211.437474)
		(end 71.24573 -211.153502)
		(width 0.20066)
		(layer "F.Cu")
		(net "M_A_CPU1_SB_DQ<19>")
	)
	(segment
		(start 59.867292 -211.35721)
		(end 59.882786 -211.341716)
		(width 0.101854)
		(layer "F.Cu")
		(net "M_A_CPU1_SB_DQ<19>")
	)
	(segment
		(start 70.82282 -212.582252)
		(end 70.603872 -212.363304)
		(width 0.20066)
		(layer "F.Cu")
		(net "M_A_CPU1_SB_DQ<19>")
	)
	(segment
		(start 85.844888 -231.207564)
		(end 85.718904 -231.207564)
		(width 0.088646)
		(layer "F.Cu")
		(net "M_A_CPU1_SB_DQ<19>")
	)
	(segment
		(start 84.16798 -231.221534)
		(end 84.096098 -231.293416)
		(width 0.088646)
		(layer "F.Cu")
		(net "M_A_CPU1_SB_DQ<19>")
	)
	(segment
		(start 84.096098 -231.293416)
		(end 83.521042 -231.293416)
		(width 0.088646)
		(layer "F.Cu")
		(net "M_A_CPU1_SB_DQ<19>")
	)
	(segment
		(start 85.544406 -231.033066)
		(end 85.437218 -231.033066)
		(width 0.088646)
		(layer "F.Cu")
		(net "M_A_CPU1_SB_DQ<19>")
	)
	(segment
		(start 59.038744 -210.916774)
		(end 59.47918 -211.35721)
		(width 0.20066)
		(layer "F.Cu")
		(net "M_A_CPU1_SB_DQ<19>")
	)
	(segment
		(start 77.077316 -216.985088)
		(end 76.982066 -216.889838)
		(width 0.1016)
		(layer "F.Cu")
		(net "M_A_CPU1_SB_DQ<19>")
	)
	(segment
		(start 87.687658 -231.332786)
		(end 87.735664 -231.28478)
		(width 0.088646)
		(layer "F.Cu")
		(net "M_A_CPU1_SB_DQ<19>")
	)
	(segment
		(start 87.017606 -231.11206)
		(end 87.007192 -231.118156)
		(width 0.088646)
		(layer "F.Cu")
		(net "M_A_CPU1_SB_DQ<19>")
	)
	(segment
		(start 70.603872 -212.079332)
		(end 71.24573 -211.437474)
		(width 0.20066)
		(layer "F.Cu")
		(net "M_A_CPU1_SB_DQ<19>")
	)
	(segment
		(start 71.106792 -212.582252)
		(end 70.82282 -212.582252)
		(width 0.20066)
		(layer "F.Cu")
		(net "M_A_CPU1_SB_DQ<19>")
	)
	(segment
		(start 62.091824 -211.341716)
		(end 62.147958 -211.341716)
		(width 0.101854)
		(layer "F.Cu")
		(net "M_A_CPU1_SB_DQ<19>")
	)
	(segment
		(start 57.503314 -210.916774)
		(end 59.038744 -210.916774)
		(width 0.20066)
		(layer "F.Cu")
		(net "M_A_CPU1_SB_DQ<19>")
	)
	(segment
		(start 86.019386 -231.033066)
		(end 85.844888 -231.207564)
		(width 0.088646)
		(layer "F.Cu")
		(net "M_A_CPU1_SB_DQ<19>")
	)
	(segment
		(start 84.941156 -231.221534)
		(end 84.16798 -231.221534)
		(width 0.088646)
		(layer "F.Cu")
		(net "M_A_CPU1_SB_DQ<19>")
	)
	(segment
		(start 87.735664 -231.28478)
		(end 87.735664 -231.090724)
		(width 0.088646)
		(layer "F.Cu")
		(net "M_A_CPU1_SB_DQ<19>")
	)
	(segment
		(start 87.205312 -231.436418)
		(end 87.308944 -231.332786)
		(width 0.088646)
		(layer "F.Cu")
		(net "M_A_CPU1_SB_DQ<19>")
	)
	(segment
		(start 76.982066 -216.889838)
		(end 72.032622 -211.940394)
		(width 0.20066)
		(layer "F.Cu")
		(net "M_A_CPU1_SB_DQ<19>")
	)
	(segment
		(start 83.297522 -231.293416)
		(end 79.252064 -227.247958)
		(width 0.1016)
		(layer "F.Cu")
		(net "M_A_CPU1_SB_DQ<19>")
	)
	(segment
		(start 71.009002 -210.916774)
		(end 65.047114 -210.916774)
		(width 0.20066)
		(layer "F.Cu")
		(net "M_A_CPU1_SB_DQ<19>")
	)
	(segment
		(start 59.47918 -211.35721)
		(end 59.822842 -211.35721)
		(width 0.20066)
		(layer "F.Cu")
		(net "M_A_CPU1_SB_DQ<19>")
	)
	(segment
		(start 59.822842 -211.35721)
		(end 59.867292 -211.35721)
		(width 0.101854)
		(layer "F.Cu")
		(net "M_A_CPU1_SB_DQ<19>")
	)
	(segment
		(start 62.541404 -210.888834)
		(end 62.72276 -210.707478)
		(width 0.20066)
		(layer "F.Cu")
		(net "M_A_CPU1_SB_DQ<19>")
	)
	(segment
		(start 85.14461 -231.108758)
		(end 84.941156 -231.221534)
		(width 0.088646)
		(layer "F.Cu")
		(net "M_A_CPU1_SB_DQ<19>")
	)
	(segment
		(start 62.99327 -210.707478)
		(end 63.202566 -210.916774)
		(width 0.20066)
		(layer "F.Cu")
		(net "M_A_CPU1_SB_DQ<19>")
	)
	(segment
		(start 87.648034 -231.003094)
		(end 87.419688 -231.003094)
		(width 0.088646)
		(layer "F.Cu")
		(net "M_A_CPU1_SB_DQ<19>")
	)
	(segment
		(start 77.078078 -216.985088)
		(end 77.077316 -216.985088)
		(width 0.101854)
		(layer "F.Cu")
		(net "M_A_CPU1_SB_DQ<19>")
	)
	(segment
		(start 87.735664 -231.090724)
		(end 87.648034 -231.003094)
		(width 0.088646)
		(layer "F.Cu")
		(net "M_A_CPU1_SB_DQ<19>")
	)
	(segment
		(start 86.157816 -231.033066)
		(end 86.019386 -231.033066)
		(width 0.088646)
		(layer "F.Cu")
		(net "M_A_CPU1_SB_DQ<19>")
	)
	(segment
		(start 59.882786 -211.341716)
		(end 62.091824 -211.341716)
		(width 0.1016)
		(layer "F.Cu")
		(net "M_A_CPU1_SB_DQ<19>")
	)
	(segment
		(start 71.24573 -211.153502)
		(end 71.009002 -210.916774)
		(width 0.20066)
		(layer "F.Cu")
		(net "M_A_CPU1_SB_DQ<19>")
	)
	(segment
		(start 71.74865 -211.940394)
		(end 71.106792 -212.582252)
		(width 0.20066)
		(layer "F.Cu")
		(net "M_A_CPU1_SB_DQ<19>")
	)
	(segment
		(start 77.646784 -223.502982)
		(end 77.646784 -217.553794)
		(width 0.1016)
		(layer "F.Cu")
		(net "M_A_CPU1_SB_DQ<19>")
	)
	(segment
		(start 62.72276 -210.707478)
		(end 62.99327 -210.707478)
		(width 0.20066)
		(layer "F.Cu")
		(net "M_A_CPU1_SB_DQ<19>")
	)
	(segment
		(start 63.202566 -210.916774)
		(end 65.047114 -210.916774)
		(width 0.20066)
		(layer "F.Cu")
		(net "M_A_CPU1_SB_DQ<19>")
	)
	(segment
		(start 87.308944 -231.332786)
		(end 87.687658 -231.332786)
		(width 0.088646)
		(layer "F.Cu")
		(net "M_A_CPU1_SB_DQ<19>")
	)
	(segment
		(start 62.426088 -211.341716)
		(end 62.541404 -211.2264)
		(width 0.20066)
		(layer "F.Cu")
		(net "M_A_CPU1_SB_DQ<19>")
	)
	(arc
		(start 85.437218 -231.033066)
		(mid 85.286093 -231.052286)
		(end 85.14461 -231.108758)
		(width 0.088646)
		(layer "F.Cu")
		(net "M_A_CPU1_SB_DQ<19>")
	)
	(arc
		(start 86.452456 -231.11206)
		(mid 86.310334 -231.053186)
		(end 86.157816 -231.033066)
		(width 0.088646)
		(layer "F.Cu")
		(net "M_A_CPU1_SB_DQ<19>")
	)
	(arc
		(start 87.419688 -231.003094)
		(mid 87.211396 -231.030819)
		(end 87.017606 -231.11206)
		(width 0.088646)
		(layer "F.Cu")
		(net "M_A_CPU1_SB_DQ<19>")
	)
	(arc
		(start 87.007192 -231.118156)
		(mid 86.729014 -231.187879)
		(end 86.452456 -231.11206)
		(width 0.088646)
		(layer "F.Cu")
		(net "M_A_CPU1_SB_DQ<19>")
	)
	(segment
		(start 83.050888 -231.909366)
		(end 78.642464 -227.500942)
		(width 0.1016)
		(layer "F.Cu")
		(net "M_A_CPU1_SB_DQ<18>")
	)
	(segment
		(start 73.601834 -217.055192)
		(end 74.309224 -216.347802)
		(width 0.20066)
		(layer "F.Cu")
		(net "M_A_CPU1_SB_DQ<18>")
	)
	(segment
		(start 85.06079 -231.70134)
		(end 84.989924 -231.630474)
		(width 0.088646)
		(layer "F.Cu")
		(net "M_A_CPU1_SB_DQ<18>")
	)
	(segment
		(start 66.07556 -212.448902)
		(end 65.907666 -212.616796)
		(width 0.20066)
		(layer "F.Cu")
		(net "M_A_CPU1_SB_DQ<18>")
	)
	(segment
		(start 59.895994 -213.041738)
		(end 62.124844 -213.041738)
		(width 0.1016)
		(layer "F.Cu")
		(net "M_A_CPU1_SB_DQ<18>")
	)
	(segment
		(start 57.503314 -212.616796)
		(end 59.137042 -212.616796)
		(width 0.20066)
		(layer "F.Cu")
		(net "M_A_CPU1_SB_DQ<18>")
	)
	(segment
		(start 62.796928 -212.433916)
		(end 63.962026 -212.433916)
		(width 0.20066)
		(layer "F.Cu")
		(net "M_A_CPU1_SB_DQ<18>")
	)
	(segment
		(start 86.358222 -231.99471)
		(end 86.294976 -232.057956)
		(width 0.088646)
		(layer "F.Cu")
		(net "M_A_CPU1_SB_DQ<18>")
	)
	(segment
		(start 77.037184 -223.755966)
		(end 77.037184 -218.79179)
		(width 0.1016)
		(layer "F.Cu")
		(net "M_A_CPU1_SB_DQ<18>")
	)
	(segment
		(start 77.037184 -218.79179)
		(end 76.561442 -218.316048)
		(width 0.1016)
		(layer "F.Cu")
		(net "M_A_CPU1_SB_DQ<18>")
	)
	(segment
		(start 62.669928 -212.560916)
		(end 62.796928 -212.433916)
		(width 0.20066)
		(layer "F.Cu")
		(net "M_A_CPU1_SB_DQ<18>")
	)
	(segment
		(start 74.309224 -216.06383)
		(end 74.090276 -215.844882)
		(width 0.20066)
		(layer "F.Cu")
		(net "M_A_CPU1_SB_DQ<18>")
	)
	(segment
		(start 74.104754 -217.558112)
		(end 73.820782 -217.558112)
		(width 0.20066)
		(layer "F.Cu")
		(net "M_A_CPU1_SB_DQ<18>")
	)
	(segment
		(start 72.595994 -216.049352)
		(end 73.303384 -215.341962)
		(width 0.20066)
		(layer "F.Cu")
		(net "M_A_CPU1_SB_DQ<18>")
	)
	(segment
		(start 84.168488 -231.909366)
		(end 83.521042 -231.909366)
		(width 0.088646)
		(layer "F.Cu")
		(net "M_A_CPU1_SB_DQ<18>")
	)
	(segment
		(start 74.812144 -216.850722)
		(end 74.104754 -217.558112)
		(width 0.20066)
		(layer "F.Cu")
		(net "M_A_CPU1_SB_DQ<18>")
	)
	(segment
		(start 84.44738 -231.630474)
		(end 84.168488 -231.909366)
		(width 0.088646)
		(layer "F.Cu")
		(net "M_A_CPU1_SB_DQ<18>")
	)
	(segment
		(start 71.175118 -214.819484)
		(end 68.804536 -212.448902)
		(width 0.20066)
		(layer "F.Cu")
		(net "M_A_CPU1_SB_DQ<18>")
	)
	(segment
		(start 59.822842 -213.055708)
		(end 59.882024 -213.055708)
		(width 0.101854)
		(layer "F.Cu")
		(net "M_A_CPU1_SB_DQ<18>")
	)
	(segment
		(start 59.882024 -213.055708)
		(end 59.895994 -213.041738)
		(width 0.101854)
		(layer "F.Cu")
		(net "M_A_CPU1_SB_DQ<18>")
	)
	(segment
		(start 85.969348 -231.911652)
		(end 85.969348 -231.735122)
		(width 0.088646)
		(layer "F.Cu")
		(net "M_A_CPU1_SB_DQ<18>")
	)
	(segment
		(start 75.096116 -216.850722)
		(end 74.812144 -216.850722)
		(width 0.20066)
		(layer "F.Cu")
		(net "M_A_CPU1_SB_DQ<18>")
	)
	(segment
		(start 62.669928 -212.919056)
		(end 62.669928 -212.560916)
		(width 0.20066)
		(layer "F.Cu")
		(net "M_A_CPU1_SB_DQ<18>")
	)
	(segment
		(start 59.575954 -213.055708)
		(end 59.822842 -213.055708)
		(width 0.20066)
		(layer "F.Cu")
		(net "M_A_CPU1_SB_DQ<18>")
	)
	(segment
		(start 85.862668 -231.628442)
		(end 85.7123 -231.628442)
		(width 0.088646)
		(layer "F.Cu")
		(net "M_A_CPU1_SB_DQ<18>")
	)
	(segment
		(start 62.147958 -213.047072)
		(end 62.541912 -213.047072)
		(width 0.20066)
		(layer "F.Cu")
		(net "M_A_CPU1_SB_DQ<18>")
	)
	(segment
		(start 73.303384 -215.341962)
		(end 73.303384 -215.035638)
		(width 0.20066)
		(layer "F.Cu")
		(net "M_A_CPU1_SB_DQ<18>")
	)
	(segment
		(start 59.137042 -212.616796)
		(end 59.575954 -213.055708)
		(width 0.20066)
		(layer "F.Cu")
		(net "M_A_CPU1_SB_DQ<18>")
	)
	(segment
		(start 86.294976 -232.057956)
		(end 86.115652 -232.057956)
		(width 0.088646)
		(layer "F.Cu")
		(net "M_A_CPU1_SB_DQ<18>")
	)
	(segment
		(start 85.969348 -231.735122)
		(end 85.862668 -231.628442)
		(width 0.088646)
		(layer "F.Cu")
		(net "M_A_CPU1_SB_DQ<18>")
	)
	(segment
		(start 76.561442 -218.316048)
		(end 75.096116 -216.850722)
		(width 0.20066)
		(layer "F.Cu")
		(net "M_A_CPU1_SB_DQ<18>")
	)
	(segment
		(start 78.642464 -227.500942)
		(end 78.642464 -225.361246)
		(width 0.1016)
		(layer "F.Cu")
		(net "M_A_CPU1_SB_DQ<18>")
	)
	(segment
		(start 64.144906 -212.616796)
		(end 65.047114 -212.616796)
		(width 0.20066)
		(layer "F.Cu")
		(net "M_A_CPU1_SB_DQ<18>")
	)
	(segment
		(start 62.124844 -213.041738)
		(end 62.130178 -213.047072)
		(width 0.101854)
		(layer "F.Cu")
		(net "M_A_CPU1_SB_DQ<18>")
	)
	(segment
		(start 73.806304 -215.844882)
		(end 73.098914 -216.552272)
		(width 0.20066)
		(layer "F.Cu")
		(net "M_A_CPU1_SB_DQ<18>")
	)
	(segment
		(start 73.820782 -217.558112)
		(end 73.601834 -217.339164)
		(width 0.20066)
		(layer "F.Cu")
		(net "M_A_CPU1_SB_DQ<18>")
	)
	(segment
		(start 78.642464 -225.361246)
		(end 77.037184 -223.755966)
		(width 0.1016)
		(layer "F.Cu")
		(net "M_A_CPU1_SB_DQ<18>")
	)
	(segment
		(start 74.309224 -216.347802)
		(end 74.309224 -216.06383)
		(width 0.20066)
		(layer "F.Cu")
		(net "M_A_CPU1_SB_DQ<18>")
	)
	(segment
		(start 63.962026 -212.433916)
		(end 64.144906 -212.616796)
		(width 0.20066)
		(layer "F.Cu")
		(net "M_A_CPU1_SB_DQ<18>")
	)
	(segment
		(start 72.814942 -216.552272)
		(end 72.595994 -216.333324)
		(width 0.20066)
		(layer "F.Cu")
		(net "M_A_CPU1_SB_DQ<18>")
	)
	(segment
		(start 74.090276 -215.844882)
		(end 73.806304 -215.844882)
		(width 0.20066)
		(layer "F.Cu")
		(net "M_A_CPU1_SB_DQ<18>")
	)
	(segment
		(start 73.08723 -214.819484)
		(end 71.175118 -214.819484)
		(width 0.20066)
		(layer "F.Cu")
		(net "M_A_CPU1_SB_DQ<18>")
	)
	(segment
		(start 84.989924 -231.630474)
		(end 84.44738 -231.630474)
		(width 0.088646)
		(layer "F.Cu")
		(net "M_A_CPU1_SB_DQ<18>")
	)
	(segment
		(start 73.303384 -215.035638)
		(end 73.08723 -214.819484)
		(width 0.20066)
		(layer "F.Cu")
		(net "M_A_CPU1_SB_DQ<18>")
	)
	(segment
		(start 62.130178 -213.047072)
		(end 62.147958 -213.047072)
		(width 0.101854)
		(layer "F.Cu")
		(net "M_A_CPU1_SB_DQ<18>")
	)
	(segment
		(start 73.098914 -216.552272)
		(end 72.814942 -216.552272)
		(width 0.20066)
		(layer "F.Cu")
		(net "M_A_CPU1_SB_DQ<18>")
	)
	(segment
		(start 85.7123 -231.628442)
		(end 85.528912 -231.81183)
		(width 0.088646)
		(layer "F.Cu")
		(net "M_A_CPU1_SB_DQ<18>")
	)
	(segment
		(start 85.528912 -231.81183)
		(end 85.329776 -231.81183)
		(width 0.088646)
		(layer "F.Cu")
		(net "M_A_CPU1_SB_DQ<18>")
	)
	(segment
		(start 72.595994 -216.333324)
		(end 72.595994 -216.049352)
		(width 0.20066)
		(layer "F.Cu")
		(net "M_A_CPU1_SB_DQ<18>")
	)
	(segment
		(start 68.804536 -212.448902)
		(end 66.07556 -212.448902)
		(width 0.20066)
		(layer "F.Cu")
		(net "M_A_CPU1_SB_DQ<18>")
	)
	(segment
		(start 86.479888 -231.99471)
		(end 86.358222 -231.99471)
		(width 0.088646)
		(layer "F.Cu")
		(net "M_A_CPU1_SB_DQ<18>")
	)
	(segment
		(start 83.521042 -231.909366)
		(end 83.050888 -231.909366)
		(width 0.1016)
		(layer "F.Cu")
		(net "M_A_CPU1_SB_DQ<18>")
	)
	(segment
		(start 62.541912 -213.047072)
		(end 62.669928 -212.919056)
		(width 0.20066)
		(layer "F.Cu")
		(net "M_A_CPU1_SB_DQ<18>")
	)
	(segment
		(start 73.601834 -217.339164)
		(end 73.601834 -217.055192)
		(width 0.20066)
		(layer "F.Cu")
		(net "M_A_CPU1_SB_DQ<18>")
	)
	(segment
		(start 65.907666 -212.616796)
		(end 65.047114 -212.616796)
		(width 0.20066)
		(layer "F.Cu")
		(net "M_A_CPU1_SB_DQ<18>")
	)
	(segment
		(start 86.735666 -232.250488)
		(end 86.479888 -231.99471)
		(width 0.088646)
		(layer "F.Cu")
		(net "M_A_CPU1_SB_DQ<18>")
	)
	(segment
		(start 86.115652 -232.057956)
		(end 85.969348 -231.911652)
		(width 0.088646)
		(layer "F.Cu")
		(net "M_A_CPU1_SB_DQ<18>")
	)
	(arc
		(start 85.329776 -231.81183)
		(mid 85.230801 -231.798839)
		(end 85.138514 -231.760776)
		(width 0.088646)
		(layer "F.Cu")
		(net "M_A_CPU1_SB_DQ<18>")
	)
	(arc
		(start 85.138514 -231.760776)
		(mid 85.097705 -231.733604)
		(end 85.06079 -231.70134)
		(width 0.088646)
		(layer "F.Cu")
		(net "M_A_CPU1_SB_DQ<18>")
	)
	(segment
		(start 61.44133 -211.766404)
		(end 61.763402 -212.088476)
		(width 0.20066)
		(layer "F.Cu")
		(net "M_A_CPU1_SB_DQ<17>")
	)
	(segment
		(start 72.00646 -213.960964)
		(end 72.225408 -214.179912)
		(width 0.20066)
		(layer "F.Cu")
		(net "M_A_CPU1_SB_DQ<17>")
	)
	(segment
		(start 61.763402 -212.088476)
		(end 62.47384 -212.088476)
		(width 0.20066)
		(layer "F.Cu")
		(net "M_A_CPU1_SB_DQ<17>")
	)
	(segment
		(start 66.765424 -211.73821)
		(end 69.057774 -211.73821)
		(width 0.20066)
		(layer "F.Cu")
		(net "M_A_CPU1_SB_DQ<17>")
	)
	(segment
		(start 78.947264 -227.37445)
		(end 83.171284 -231.59847)
		(width 0.1016)
		(layer "F.Cu")
		(net "M_A_CPU1_SB_DQ<17>")
	)
	(segment
		(start 72.00646 -213.676992)
		(end 72.00646 -213.960964)
		(width 0.20066)
		(layer "F.Cu")
		(net "M_A_CPU1_SB_DQ<17>")
	)
	(segment
		(start 55.583328 -212.027008)
		(end 55.583328 -211.496148)
		(width 0.20066)
		(layer "F.Cu")
		(net "M_A_CPU1_SB_DQ<17>")
	)
	(segment
		(start 71.259446 -213.418166)
		(end 71.777352 -212.90026)
		(width 0.20066)
		(layer "F.Cu")
		(net "M_A_CPU1_SB_DQ<17>")
	)
	(segment
		(start 55.4609 -212.149436)
		(end 55.583328 -212.027008)
		(width 0.20066)
		(layer "F.Cu")
		(net "M_A_CPU1_SB_DQ<17>")
	)
	(segment
		(start 61.441076 -211.766658)
		(end 61.44133 -211.766404)
		(width 0.20066)
		(layer "F.Cu")
		(net "M_A_CPU1_SB_DQ<17>")
	)
	(segment
		(start 84.107528 -231.59847)
		(end 84.26958 -231.436418)
		(width 0.088646)
		(layer "F.Cu")
		(net "M_A_CPU1_SB_DQ<17>")
	)
	(segment
		(start 72.751188 -213.938104)
		(end 73.110344 -213.938104)
		(width 0.20066)
		(layer "F.Cu")
		(net "M_A_CPU1_SB_DQ<17>")
	)
	(segment
		(start 66.362326 -211.335112)
		(end 66.765424 -211.73821)
		(width 0.20066)
		(layer "F.Cu")
		(net "M_A_CPU1_SB_DQ<17>")
	)
	(segment
		(start 72.061324 -212.90026)
		(end 72.280272 -213.119208)
		(width 0.20066)
		(layer "F.Cu")
		(net "M_A_CPU1_SB_DQ<17>")
	)
	(segment
		(start 55.583328 -211.496148)
		(end 55.743856 -211.33562)
		(width 0.20066)
		(layer "F.Cu")
		(net "M_A_CPU1_SB_DQ<17>")
	)
	(segment
		(start 83.171284 -231.59847)
		(end 83.521042 -231.59847)
		(width 0.1016)
		(layer "F.Cu")
		(net "M_A_CPU1_SB_DQ<17>")
	)
	(segment
		(start 62.795912 -211.766404)
		(end 63.285624 -211.766404)
		(width 0.20066)
		(layer "F.Cu")
		(net "M_A_CPU1_SB_DQ<17>")
	)
	(segment
		(start 64.063372 -211.341716)
		(end 65.903348 -211.341716)
		(width 0.1016)
		(layer "F.Cu")
		(net "M_A_CPU1_SB_DQ<17>")
	)
	(segment
		(start 56.398922 -211.341716)
		(end 58.349134 -211.341716)
		(width 0.1016)
		(layer "F.Cu")
		(net "M_A_CPU1_SB_DQ<17>")
	)
	(segment
		(start 53.403246 -211.766658)
		(end 54.524402 -211.766658)
		(width 0.20066)
		(layer "F.Cu")
		(net "M_A_CPU1_SB_DQ<17>")
	)
	(segment
		(start 63.721488 -211.33054)
		(end 64.027812 -211.33054)
		(width 0.20066)
		(layer "F.Cu")
		(net "M_A_CPU1_SB_DQ<17>")
	)
	(segment
		(start 65.903348 -211.341716)
		(end 66.154808 -211.341716)
		(width 0.101854)
		(layer "F.Cu")
		(net "M_A_CPU1_SB_DQ<17>")
	)
	(segment
		(start 72.280272 -213.119208)
		(end 72.280272 -213.40318)
		(width 0.20066)
		(layer "F.Cu")
		(net "M_A_CPU1_SB_DQ<17>")
	)
	(segment
		(start 55.743856 -211.33562)
		(end 56.37911 -211.33562)
		(width 0.20066)
		(layer "F.Cu")
		(net "M_A_CPU1_SB_DQ<17>")
	)
	(segment
		(start 56.37911 -211.33562)
		(end 56.398922 -211.341716)
		(width 0.1016)
		(layer "F.Cu")
		(net "M_A_CPU1_SB_DQ<17>")
	)
	(segment
		(start 64.052196 -211.33054)
		(end 64.063372 -211.341716)
		(width 0.101854)
		(layer "F.Cu")
		(net "M_A_CPU1_SB_DQ<17>")
	)
	(segment
		(start 69.057774 -211.73821)
		(end 70.73773 -213.418166)
		(width 0.20066)
		(layer "F.Cu")
		(net "M_A_CPU1_SB_DQ<17>")
	)
	(segment
		(start 63.285624 -211.766404)
		(end 63.721488 -211.33054)
		(width 0.20066)
		(layer "F.Cu")
		(net "M_A_CPU1_SB_DQ<17>")
	)
	(segment
		(start 64.027812 -211.33054)
		(end 64.052196 -211.33054)
		(width 0.101854)
		(layer "F.Cu")
		(net "M_A_CPU1_SB_DQ<17>")
	)
	(segment
		(start 66.161412 -211.335112)
		(end 66.362326 -211.335112)
		(width 0.20066)
		(layer "F.Cu")
		(net "M_A_CPU1_SB_DQ<17>")
	)
	(segment
		(start 72.50938 -214.179912)
		(end 72.751188 -213.938104)
		(width 0.20066)
		(layer "F.Cu")
		(net "M_A_CPU1_SB_DQ<17>")
	)
	(segment
		(start 66.154808 -211.341716)
		(end 66.161412 -211.335112)
		(width 0.101854)
		(layer "F.Cu")
		(net "M_A_CPU1_SB_DQ<17>")
	)
	(segment
		(start 54.90718 -212.149436)
		(end 55.4609 -212.149436)
		(width 0.20066)
		(layer "F.Cu")
		(net "M_A_CPU1_SB_DQ<17>")
	)
	(segment
		(start 58.349134 -211.341716)
		(end 58.704226 -211.341716)
		(width 0.101854)
		(layer "F.Cu")
		(net "M_A_CPU1_SB_DQ<17>")
	)
	(segment
		(start 60.947046 -211.766658)
		(end 61.441076 -211.766658)
		(width 0.20066)
		(layer "F.Cu")
		(net "M_A_CPU1_SB_DQ<17>")
	)
	(segment
		(start 77.341984 -218.169744)
		(end 77.341984 -223.629474)
		(width 0.1016)
		(layer "F.Cu")
		(net "M_A_CPU1_SB_DQ<17>")
	)
	(segment
		(start 77.341984 -223.629474)
		(end 78.947264 -225.234754)
		(width 0.1016)
		(layer "F.Cu")
		(net "M_A_CPU1_SB_DQ<17>")
	)
	(segment
		(start 77.157072 -217.984832)
		(end 77.341984 -218.169744)
		(width 0.1016)
		(layer "F.Cu")
		(net "M_A_CPU1_SB_DQ<17>")
	)
	(segment
		(start 73.110344 -213.938104)
		(end 77.157072 -217.984832)
		(width 0.20066)
		(layer "F.Cu")
		(net "M_A_CPU1_SB_DQ<17>")
	)
	(segment
		(start 58.704226 -211.341716)
		(end 58.840878 -211.341716)
		(width 0.20066)
		(layer "F.Cu")
		(net "M_A_CPU1_SB_DQ<17>")
	)
	(segment
		(start 54.524402 -211.766658)
		(end 54.90718 -212.149436)
		(width 0.20066)
		(layer "F.Cu")
		(net "M_A_CPU1_SB_DQ<17>")
	)
	(segment
		(start 83.521042 -231.59847)
		(end 84.107528 -231.59847)
		(width 0.088646)
		(layer "F.Cu")
		(net "M_A_CPU1_SB_DQ<17>")
	)
	(segment
		(start 72.225408 -214.179912)
		(end 72.50938 -214.179912)
		(width 0.20066)
		(layer "F.Cu")
		(net "M_A_CPU1_SB_DQ<17>")
	)
	(segment
		(start 84.26958 -231.436418)
		(end 85.325712 -231.436418)
		(width 0.088646)
		(layer "F.Cu")
		(net "M_A_CPU1_SB_DQ<17>")
	)
	(segment
		(start 58.840878 -211.341716)
		(end 59.26582 -211.766658)
		(width 0.20066)
		(layer "F.Cu")
		(net "M_A_CPU1_SB_DQ<17>")
	)
	(segment
		(start 70.73773 -213.418166)
		(end 71.259446 -213.418166)
		(width 0.20066)
		(layer "F.Cu")
		(net "M_A_CPU1_SB_DQ<17>")
	)
	(segment
		(start 71.777352 -212.90026)
		(end 72.061324 -212.90026)
		(width 0.20066)
		(layer "F.Cu")
		(net "M_A_CPU1_SB_DQ<17>")
	)
	(segment
		(start 78.947264 -225.234754)
		(end 78.947264 -227.37445)
		(width 0.1016)
		(layer "F.Cu")
		(net "M_A_CPU1_SB_DQ<17>")
	)
	(segment
		(start 62.47384 -212.088476)
		(end 62.795912 -211.766404)
		(width 0.20066)
		(layer "F.Cu")
		(net "M_A_CPU1_SB_DQ<17>")
	)
	(segment
		(start 59.26582 -211.766658)
		(end 60.947046 -211.766658)
		(width 0.20066)
		(layer "F.Cu")
		(net "M_A_CPU1_SB_DQ<17>")
	)
	(segment
		(start 72.280272 -213.40318)
		(end 72.00646 -213.676992)
		(width 0.20066)
		(layer "F.Cu")
		(net "M_A_CPU1_SB_DQ<17>")
	)
	(segment
		(start 66.147188 -213.031324)
		(end 66.147188 -213.039198)
		(width 0.101854)
		(layer "F.Cu")
		(net "M_A_CPU1_SB_DQ<16>")
	)
	(segment
		(start 64.185292 -213.041738)
		(end 63.990728 -213.041738)
		(width 0.101854)
		(layer "F.Cu")
		(net "M_A_CPU1_SB_DQ<16>")
	)
	(segment
		(start 66.483992 -213.175596)
		(end 66.339466 -213.03107)
		(width 0.20066)
		(layer "F.Cu")
		(net "M_A_CPU1_SB_DQ<16>")
	)
	(segment
		(start 75.570334 -219.486734)
		(end 74.844656 -219.486734)
		(width 0.20066)
		(layer "F.Cu")
		(net "M_A_CPU1_SB_DQ<16>")
	)
	(segment
		(start 66.186812 -213.03107)
		(end 66.147442 -213.03107)
		(width 0.101854)
		(layer "F.Cu")
		(net "M_A_CPU1_SB_DQ<16>")
	)
	(segment
		(start 74.200766 -218.558872)
		(end 73.916794 -218.558872)
		(width 0.20066)
		(layer "F.Cu")
		(net "M_A_CPU1_SB_DQ<16>")
	)
	(segment
		(start 74.908156 -217.851482)
		(end 74.200766 -218.558872)
		(width 0.20066)
		(layer "F.Cu")
		(net "M_A_CPU1_SB_DQ<16>")
	)
	(segment
		(start 76.732384 -219.81668)
		(end 76.402438 -219.486734)
		(width 0.1016)
		(layer "F.Cu")
		(net "M_A_CPU1_SB_DQ<16>")
	)
	(segment
		(start 63.265812 -213.028022)
		(end 62.827154 -213.46668)
		(width 0.20066)
		(layer "F.Cu")
		(net "M_A_CPU1_SB_DQ<16>")
	)
	(segment
		(start 58.349134 -213.041738)
		(end 58.414666 -213.022942)
		(width 0.1016)
		(layer "F.Cu")
		(net "M_A_CPU1_SB_DQ<16>")
	)
	(segment
		(start 66.147188 -213.039198)
		(end 66.144648 -213.041738)
		(width 0.101854)
		(layer "F.Cu")
		(net "M_A_CPU1_SB_DQ<16>")
	)
	(segment
		(start 55.583328 -213.484206)
		(end 55.583328 -213.19617)
		(width 0.20066)
		(layer "F.Cu")
		(net "M_A_CPU1_SB_DQ<16>")
	)
	(segment
		(start 56.37911 -213.000336)
		(end 56.407812 -213.000336)
		(width 0.101854)
		(layer "F.Cu")
		(net "M_A_CPU1_SB_DQ<16>")
	)
	(segment
		(start 55.39486 -213.672674)
		(end 55.583328 -213.484206)
		(width 0.20066)
		(layer "F.Cu")
		(net "M_A_CPU1_SB_DQ<16>")
	)
	(segment
		(start 66.147442 -213.03107)
		(end 66.147188 -213.031324)
		(width 0.101854)
		(layer "F.Cu")
		(net "M_A_CPU1_SB_DQ<16>")
	)
	(segment
		(start 54.713378 -213.46668)
		(end 54.919372 -213.672674)
		(width 0.20066)
		(layer "F.Cu")
		(net "M_A_CPU1_SB_DQ<16>")
	)
	(segment
		(start 75.411076 -218.07043)
		(end 75.192128 -217.851482)
		(width 0.20066)
		(layer "F.Cu")
		(net "M_A_CPU1_SB_DQ<16>")
	)
	(segment
		(start 66.144648 -213.041738)
		(end 64.185292 -213.041738)
		(width 0.1016)
		(layer "F.Cu")
		(net "M_A_CPU1_SB_DQ<16>")
	)
	(segment
		(start 62.827154 -213.46668)
		(end 60.947046 -213.46668)
		(width 0.20066)
		(layer "F.Cu")
		(net "M_A_CPU1_SB_DQ<16>")
	)
	(segment
		(start 63.977012 -213.028022)
		(end 63.265812 -213.028022)
		(width 0.20066)
		(layer "F.Cu")
		(net "M_A_CPU1_SB_DQ<16>")
	)
	(segment
		(start 73.916794 -218.558872)
		(end 68.533518 -213.175596)
		(width 0.20066)
		(layer "F.Cu")
		(net "M_A_CPU1_SB_DQ<16>")
	)
	(segment
		(start 58.414666 -213.022942)
		(end 58.704226 -213.022942)
		(width 0.101854)
		(layer "F.Cu")
		(net "M_A_CPU1_SB_DQ<16>")
	)
	(segment
		(start 58.704226 -213.022942)
		(end 58.889138 -213.022942)
		(width 0.20066)
		(layer "F.Cu")
		(net "M_A_CPU1_SB_DQ<16>")
	)
	(segment
		(start 74.703686 -219.061792)
		(end 75.411076 -218.354402)
		(width 0.20066)
		(layer "F.Cu")
		(net "M_A_CPU1_SB_DQ<16>")
	)
	(segment
		(start 75.192128 -217.851482)
		(end 74.908156 -217.851482)
		(width 0.20066)
		(layer "F.Cu")
		(net "M_A_CPU1_SB_DQ<16>")
	)
	(segment
		(start 68.533518 -213.175596)
		(end 66.483992 -213.175596)
		(width 0.20066)
		(layer "F.Cu")
		(net "M_A_CPU1_SB_DQ<16>")
	)
	(segment
		(start 55.583328 -213.19617)
		(end 55.779162 -213.000336)
		(width 0.20066)
		(layer "F.Cu")
		(net "M_A_CPU1_SB_DQ<16>")
	)
	(segment
		(start 84.856066 -231.876092)
		(end 84.49818 -231.876092)
		(width 0.088646)
		(layer "F.Cu")
		(net "M_A_CPU1_SB_DQ<16>")
	)
	(segment
		(start 74.703686 -219.345764)
		(end 74.703686 -219.061792)
		(width 0.20066)
		(layer "F.Cu")
		(net "M_A_CPU1_SB_DQ<16>")
	)
	(segment
		(start 56.610758 -213.041738)
		(end 58.349134 -213.041738)
		(width 0.1016)
		(layer "F.Cu")
		(net "M_A_CPU1_SB_DQ<16>")
	)
	(segment
		(start 82.968846 -232.258616)
		(end 78.337664 -227.627434)
		(width 0.1016)
		(layer "F.Cu")
		(net "M_A_CPU1_SB_DQ<16>")
	)
	(segment
		(start 59.332876 -213.46668)
		(end 60.947046 -213.46668)
		(width 0.20066)
		(layer "F.Cu")
		(net "M_A_CPU1_SB_DQ<16>")
	)
	(segment
		(start 66.339466 -213.03107)
		(end 66.186812 -213.03107)
		(width 0.20066)
		(layer "F.Cu")
		(net "M_A_CPU1_SB_DQ<16>")
	)
	(segment
		(start 84.49818 -231.876092)
		(end 84.115656 -232.258616)
		(width 0.088646)
		(layer "F.Cu")
		(net "M_A_CPU1_SB_DQ<16>")
	)
	(segment
		(start 58.889138 -213.022942)
		(end 59.332876 -213.46668)
		(width 0.20066)
		(layer "F.Cu")
		(net "M_A_CPU1_SB_DQ<16>")
	)
	(segment
		(start 54.919372 -213.672674)
		(end 55.39486 -213.672674)
		(width 0.20066)
		(layer "F.Cu")
		(net "M_A_CPU1_SB_DQ<16>")
	)
	(segment
		(start 78.337664 -225.487738)
		(end 76.732384 -223.882458)
		(width 0.1016)
		(layer "F.Cu")
		(net "M_A_CPU1_SB_DQ<16>")
	)
	(segment
		(start 85.353906 -232.108248)
		(end 85.043264 -231.92613)
		(width 0.088646)
		(layer "F.Cu")
		(net "M_A_CPU1_SB_DQ<16>")
	)
	(segment
		(start 53.403246 -213.46668)
		(end 54.713378 -213.46668)
		(width 0.20066)
		(layer "F.Cu")
		(net "M_A_CPU1_SB_DQ<16>")
	)
	(segment
		(start 63.990728 -213.041738)
		(end 63.977012 -213.028022)
		(width 0.101854)
		(layer "F.Cu")
		(net "M_A_CPU1_SB_DQ<16>")
	)
	(segment
		(start 78.337664 -227.627434)
		(end 78.337664 -225.487738)
		(width 0.1016)
		(layer "F.Cu")
		(net "M_A_CPU1_SB_DQ<16>")
	)
	(segment
		(start 85.795866 -232.250488)
		(end 85.353906 -232.108248)
		(width 0.088646)
		(layer "F.Cu")
		(net "M_A_CPU1_SB_DQ<16>")
	)
	(segment
		(start 75.411076 -218.354402)
		(end 75.411076 -218.07043)
		(width 0.20066)
		(layer "F.Cu")
		(net "M_A_CPU1_SB_DQ<16>")
	)
	(segment
		(start 56.407812 -213.000336)
		(end 56.475376 -213.000336)
		(width 0.1016)
		(layer "F.Cu")
		(net "M_A_CPU1_SB_DQ<16>")
	)
	(segment
		(start 56.475376 -213.000336)
		(end 56.610758 -213.041738)
		(width 0.1016)
		(layer "F.Cu")
		(net "M_A_CPU1_SB_DQ<16>")
	)
	(segment
		(start 84.115656 -232.258616)
		(end 83.521296 -232.258616)
		(width 0.088646)
		(layer "F.Cu")
		(net "M_A_CPU1_SB_DQ<16>")
	)
	(segment
		(start 55.779162 -213.000336)
		(end 56.37911 -213.000336)
		(width 0.20066)
		(layer "F.Cu")
		(net "M_A_CPU1_SB_DQ<16>")
	)
	(segment
		(start 76.402438 -219.486734)
		(end 75.570334 -219.486734)
		(width 0.1016)
		(layer "F.Cu")
		(net "M_A_CPU1_SB_DQ<16>")
	)
	(segment
		(start 76.732384 -223.882458)
		(end 76.732384 -219.81668)
		(width 0.1016)
		(layer "F.Cu")
		(net "M_A_CPU1_SB_DQ<16>")
	)
	(segment
		(start 74.844656 -219.486734)
		(end 74.703686 -219.345764)
		(width 0.20066)
		(layer "F.Cu")
		(net "M_A_CPU1_SB_DQ<16>")
	)
	(segment
		(start 83.521296 -232.258616)
		(end 82.968846 -232.258616)
		(width 0.1016)
		(layer "F.Cu")
		(net "M_A_CPU1_SB_DQ<16>")
	)
	(arc
		(start 85.043264 -231.92613)
		(mid 84.952957 -231.888801)
		(end 84.856066 -231.876092)
		(width 0.088646)
		(layer "F.Cu")
		(net "M_A_CPU1_SB_DQ<16>")
	)
	(segment
		(start 85.532468 -233.501946)
		(end 85.514942 -233.501946)
		(width 0.088646)
		(layer "F.Cu")
		(net "M_A_CPU1_SB_DQ<15>")
	)
	(segment
		(start 86.304374 -233.700066)
		(end 86.041484 -233.437176)
		(width 0.088646)
		(layer "F.Cu")
		(net "M_A_CPU1_SB_DQ<15>")
	)
	(segment
		(start 59.85129 -214.741506)
		(end 59.862212 -214.741506)
		(width 0.101854)
		(layer "F.Cu")
		(net "M_A_CPU1_SB_DQ<15>")
	)
	(segment
		(start 75.21321 -222.019622)
		(end 75.21321 -221.709742)
		(width 0.20066)
		(layer "F.Cu")
		(net "M_A_CPU1_SB_DQ<15>")
	)
	(segment
		(start 74.335386 -223.843342)
		(end 74.536046 -223.642682)
		(width 0.20066)
		(layer "F.Cu")
		(net "M_A_CPU1_SB_DQ<15>")
	)
	(segment
		(start 74.335386 -220.830902)
		(end 67.56781 -214.063326)
		(width 0.20066)
		(layer "F.Cu")
		(net "M_A_CPU1_SB_DQ<15>")
	)
	(segment
		(start 62.669928 -214.260684)
		(end 62.796928 -214.133684)
		(width 0.20066)
		(layer "F.Cu")
		(net "M_A_CPU1_SB_DQ<15>")
	)
	(segment
		(start 75.01255 -222.931482)
		(end 74.536046 -222.931482)
		(width 0.20066)
		(layer "F.Cu")
		(net "M_A_CPU1_SB_DQ<15>")
	)
	(segment
		(start 62.548516 -214.741506)
		(end 62.669928 -214.620094)
		(width 0.20066)
		(layer "F.Cu")
		(net "M_A_CPU1_SB_DQ<15>")
	)
	(segment
		(start 74.335386 -222.420942)
		(end 74.536046 -222.220282)
		(width 0.20066)
		(layer "F.Cu")
		(net "M_A_CPU1_SB_DQ<15>")
	)
	(segment
		(start 61.863986 -214.741506)
		(end 62.147958 -214.741506)
		(width 0.101854)
		(layer "F.Cu")
		(net "M_A_CPU1_SB_DQ<15>")
	)
	(segment
		(start 59.862212 -214.741506)
		(end 61.863986 -214.741506)
		(width 0.1016)
		(layer "F.Cu")
		(net "M_A_CPU1_SB_DQ<15>")
	)
	(segment
		(start 67.56781 -214.063326)
		(end 65.81648 -214.063326)
		(width 0.20066)
		(layer "F.Cu")
		(net "M_A_CPU1_SB_DQ<15>")
	)
	(segment
		(start 75.01255 -221.509082)
		(end 74.536046 -221.509082)
		(width 0.20066)
		(layer "F.Cu")
		(net "M_A_CPU1_SB_DQ<15>")
	)
	(segment
		(start 62.796928 -214.133684)
		(end 63.93307 -214.133684)
		(width 0.20066)
		(layer "F.Cu")
		(net "M_A_CPU1_SB_DQ<15>")
	)
	(segment
		(start 75.01255 -222.220282)
		(end 75.21321 -222.019622)
		(width 0.20066)
		(layer "F.Cu")
		(net "M_A_CPU1_SB_DQ<15>")
	)
	(segment
		(start 85.634576 -233.437176)
		(end 85.596222 -233.47553)
		(width 0.088646)
		(layer "F.Cu")
		(net "M_A_CPU1_SB_DQ<15>")
	)
	(segment
		(start 84.31657 -233.126026)
		(end 84.054696 -233.126026)
		(width 0.088646)
		(layer "F.Cu")
		(net "M_A_CPU1_SB_DQ<15>")
	)
	(segment
		(start 75.21321 -221.709742)
		(end 75.01255 -221.509082)
		(width 0.20066)
		(layer "F.Cu")
		(net "M_A_CPU1_SB_DQ<15>")
	)
	(segment
		(start 59.103006 -214.316564)
		(end 59.54268 -214.756238)
		(width 0.20066)
		(layer "F.Cu")
		(net "M_A_CPU1_SB_DQ<15>")
	)
	(segment
		(start 84.657946 -233.282744)
		(end 84.473288 -233.282744)
		(width 0.088646)
		(layer "F.Cu")
		(net "M_A_CPU1_SB_DQ<15>")
	)
	(segment
		(start 57.503314 -214.316564)
		(end 59.103006 -214.316564)
		(width 0.20066)
		(layer "F.Cu")
		(net "M_A_CPU1_SB_DQ<15>")
	)
	(segment
		(start 64.11595 -214.316564)
		(end 65.047114 -214.316564)
		(width 0.20066)
		(layer "F.Cu")
		(net "M_A_CPU1_SB_DQ<15>")
	)
	(segment
		(start 59.822842 -214.756238)
		(end 59.836558 -214.756238)
		(width 0.101854)
		(layer "F.Cu")
		(net "M_A_CPU1_SB_DQ<15>")
	)
	(segment
		(start 74.536046 -221.509082)
		(end 74.335386 -221.308422)
		(width 0.20066)
		(layer "F.Cu")
		(net "M_A_CPU1_SB_DQ<15>")
	)
	(segment
		(start 59.836558 -214.756238)
		(end 59.85129 -214.741506)
		(width 0.101854)
		(layer "F.Cu")
		(net "M_A_CPU1_SB_DQ<15>")
	)
	(segment
		(start 62.669928 -214.620094)
		(end 62.669928 -214.260684)
		(width 0.20066)
		(layer "F.Cu")
		(net "M_A_CPU1_SB_DQ<15>")
	)
	(segment
		(start 84.473288 -233.282744)
		(end 84.31657 -233.126026)
		(width 0.088646)
		(layer "F.Cu")
		(net "M_A_CPU1_SB_DQ<15>")
	)
	(segment
		(start 74.335386 -221.308422)
		(end 74.335386 -220.830902)
		(width 0.20066)
		(layer "F.Cu")
		(net "M_A_CPU1_SB_DQ<15>")
	)
	(segment
		(start 76.670662 -225.68916)
		(end 75.725528 -224.744026)
		(width 0.20066)
		(layer "F.Cu")
		(net "M_A_CPU1_SB_DQ<15>")
	)
	(segment
		(start 77.463396 -226.481894)
		(end 76.670662 -225.68916)
		(width 0.1016)
		(layer "F.Cu")
		(net "M_A_CPU1_SB_DQ<15>")
	)
	(segment
		(start 74.555858 -224.744026)
		(end 74.335386 -224.523554)
		(width 0.20066)
		(layer "F.Cu")
		(net "M_A_CPU1_SB_DQ<15>")
	)
	(segment
		(start 84.054696 -233.126026)
		(end 82.98815 -233.126026)
		(width 0.1016)
		(layer "F.Cu")
		(net "M_A_CPU1_SB_DQ<15>")
	)
	(segment
		(start 75.01255 -223.642682)
		(end 75.21321 -223.442022)
		(width 0.20066)
		(layer "F.Cu")
		(net "M_A_CPU1_SB_DQ<15>")
	)
	(segment
		(start 74.536046 -222.931482)
		(end 74.335386 -222.730822)
		(width 0.20066)
		(layer "F.Cu")
		(net "M_A_CPU1_SB_DQ<15>")
	)
	(segment
		(start 59.54268 -214.756238)
		(end 59.822842 -214.756238)
		(width 0.20066)
		(layer "F.Cu")
		(net "M_A_CPU1_SB_DQ<15>")
	)
	(segment
		(start 82.98815 -233.126026)
		(end 77.463396 -227.601272)
		(width 0.1016)
		(layer "F.Cu")
		(net "M_A_CPU1_SB_DQ<15>")
	)
	(segment
		(start 65.81648 -214.063326)
		(end 65.563242 -214.316564)
		(width 0.20066)
		(layer "F.Cu")
		(net "M_A_CPU1_SB_DQ<15>")
	)
	(segment
		(start 75.21321 -223.442022)
		(end 75.21321 -223.132142)
		(width 0.20066)
		(layer "F.Cu")
		(net "M_A_CPU1_SB_DQ<15>")
	)
	(segment
		(start 74.335386 -222.730822)
		(end 74.335386 -222.420942)
		(width 0.20066)
		(layer "F.Cu")
		(net "M_A_CPU1_SB_DQ<15>")
	)
	(segment
		(start 74.335386 -224.523554)
		(end 74.335386 -223.843342)
		(width 0.20066)
		(layer "F.Cu")
		(net "M_A_CPU1_SB_DQ<15>")
	)
	(segment
		(start 77.463396 -227.601272)
		(end 77.463396 -226.481894)
		(width 0.1016)
		(layer "F.Cu")
		(net "M_A_CPU1_SB_DQ<15>")
	)
	(segment
		(start 63.93307 -214.133684)
		(end 64.11595 -214.316564)
		(width 0.20066)
		(layer "F.Cu")
		(net "M_A_CPU1_SB_DQ<15>")
	)
	(segment
		(start 85.183472 -233.414824)
		(end 85.137244 -233.388662)
		(width 0.088646)
		(layer "F.Cu")
		(net "M_A_CPU1_SB_DQ<15>")
	)
	(segment
		(start 84.93252 -233.318304)
		(end 84.657946 -233.282744)
		(width 0.088646)
		(layer "F.Cu")
		(net "M_A_CPU1_SB_DQ<15>")
	)
	(segment
		(start 65.563242 -214.316564)
		(end 65.047114 -214.316564)
		(width 0.20066)
		(layer "F.Cu")
		(net "M_A_CPU1_SB_DQ<15>")
	)
	(segment
		(start 62.147958 -214.741506)
		(end 62.548516 -214.741506)
		(width 0.20066)
		(layer "F.Cu")
		(net "M_A_CPU1_SB_DQ<15>")
	)
	(segment
		(start 75.725528 -224.744026)
		(end 74.555858 -224.744026)
		(width 0.20066)
		(layer "F.Cu")
		(net "M_A_CPU1_SB_DQ<15>")
	)
	(segment
		(start 75.21321 -223.132142)
		(end 75.01255 -222.931482)
		(width 0.20066)
		(layer "F.Cu")
		(net "M_A_CPU1_SB_DQ<15>")
	)
	(segment
		(start 74.536046 -223.642682)
		(end 75.01255 -223.642682)
		(width 0.20066)
		(layer "F.Cu")
		(net "M_A_CPU1_SB_DQ<15>")
	)
	(segment
		(start 74.536046 -222.220282)
		(end 75.01255 -222.220282)
		(width 0.20066)
		(layer "F.Cu")
		(net "M_A_CPU1_SB_DQ<15>")
	)
	(arc
		(start 86.735666 -233.87812)
		(mid 86.502242 -233.832145)
		(end 86.304374 -233.700066)
		(width 0.088646)
		(layer "F.Cu")
		(net "M_A_CPU1_SB_DQ<15>")
	)
	(arc
		(start 85.514942 -233.501946)
		(mid 85.343562 -233.479847)
		(end 85.183472 -233.414824)
		(width 0.088646)
		(layer "F.Cu")
		(net "M_A_CPU1_SB_DQ<15>")
	)
	(arc
		(start 86.041484 -233.437176)
		(mid 85.83803 -233.352903)
		(end 85.634576 -233.437176)
		(width 0.088646)
		(layer "F.Cu")
		(net "M_A_CPU1_SB_DQ<15>")
	)
	(arc
		(start 85.596222 -233.47553)
		(mid 85.566971 -233.495075)
		(end 85.532468 -233.501946)
		(width 0.088646)
		(layer "F.Cu")
		(net "M_A_CPU1_SB_DQ<15>")
	)
	(arc
		(start 85.137244 -233.388662)
		(mid 85.038283 -233.343584)
		(end 84.93252 -233.318304)
		(width 0.088646)
		(layer "F.Cu")
		(net "M_A_CPU1_SB_DQ<15>")
	)
	(segment
		(start 63.14313 -215.814656)
		(end 63.34506 -216.016586)
		(width 0.20066)
		(layer "F.Cu")
		(net "M_A_CPU1_SB_DQ<14>")
	)
	(segment
		(start 73.013062 -221.340172)
		(end 67.079622 -215.406732)
		(width 0.20066)
		(layer "F.Cu")
		(net "M_A_CPU1_SB_DQ<14>")
	)
	(segment
		(start 73.522332 -226.064826)
		(end 73.274936 -226.064826)
		(width 0.20066)
		(layer "F.Cu")
		(net "M_A_CPU1_SB_DQ<14>")
	)
	(segment
		(start 76.108052 -226.941888)
		(end 75.569572 -226.941888)
		(width 0.20066)
		(layer "F.Cu")
		(net "M_A_CPU1_SB_DQ<14>")
	)
	(segment
		(start 74.233532 -227.192078)
		(end 73.923652 -227.192078)
		(width 0.20066)
		(layer "F.Cu")
		(net "M_A_CPU1_SB_DQ<14>")
	)
	(segment
		(start 66.567558 -215.406732)
		(end 65.957704 -216.016586)
		(width 0.20066)
		(layer "F.Cu")
		(net "M_A_CPU1_SB_DQ<14>")
	)
	(segment
		(start 73.274936 -226.064826)
		(end 73.013062 -225.802952)
		(width 0.20066)
		(layer "F.Cu")
		(net "M_A_CPU1_SB_DQ<14>")
	)
	(segment
		(start 62.827916 -215.814656)
		(end 63.14313 -215.814656)
		(width 0.20066)
		(layer "F.Cu")
		(net "M_A_CPU1_SB_DQ<14>")
	)
	(segment
		(start 65.957704 -216.016586)
		(end 65.047114 -216.016586)
		(width 0.20066)
		(layer "F.Cu")
		(net "M_A_CPU1_SB_DQ<14>")
	)
	(segment
		(start 75.335892 -226.258628)
		(end 75.14209 -226.064826)
		(width 0.20066)
		(layer "F.Cu")
		(net "M_A_CPU1_SB_DQ<14>")
	)
	(segment
		(start 75.569572 -226.941888)
		(end 75.335892 -226.708208)
		(width 0.20066)
		(layer "F.Cu")
		(net "M_A_CPU1_SB_DQ<14>")
	)
	(segment
		(start 57.503314 -216.016586)
		(end 59.092592 -216.016586)
		(width 0.20066)
		(layer "F.Cu")
		(net "M_A_CPU1_SB_DQ<14>")
	)
	(segment
		(start 76.689204 -227.689664)
		(end 76.689204 -227.52304)
		(width 0.1016)
		(layer "F.Cu")
		(net "M_A_CPU1_SB_DQ<14>")
	)
	(segment
		(start 83.521296 -234.170474)
		(end 83.170014 -234.170474)
		(width 0.1016)
		(layer "F.Cu")
		(net "M_A_CPU1_SB_DQ<14>")
	)
	(segment
		(start 84.222082 -234.533186)
		(end 83.85937 -234.170474)
		(width 0.088646)
		(layer "F.Cu")
		(net "M_A_CPU1_SB_DQ<14>")
	)
	(segment
		(start 83.170014 -234.170474)
		(end 76.689204 -227.689664)
		(width 0.1016)
		(layer "F.Cu")
		(net "M_A_CPU1_SB_DQ<14>")
	)
	(segment
		(start 84.848446 -234.533186)
		(end 84.222082 -234.533186)
		(width 0.088646)
		(layer "F.Cu")
		(net "M_A_CPU1_SB_DQ<14>")
	)
	(segment
		(start 73.923652 -227.192078)
		(end 73.722992 -226.991418)
		(width 0.20066)
		(layer "F.Cu")
		(net "M_A_CPU1_SB_DQ<14>")
	)
	(segment
		(start 60.088018 -216.441528)
		(end 61.87567 -216.441528)
		(width 0.1016)
		(layer "F.Cu")
		(net "M_A_CPU1_SB_DQ<14>")
	)
	(segment
		(start 59.527694 -216.451688)
		(end 59.822842 -216.451688)
		(width 0.20066)
		(layer "F.Cu")
		(net "M_A_CPU1_SB_DQ<14>")
	)
	(segment
		(start 59.092592 -216.016586)
		(end 59.527694 -216.451688)
		(width 0.20066)
		(layer "F.Cu")
		(net "M_A_CPU1_SB_DQ<14>")
	)
	(segment
		(start 73.013062 -225.802952)
		(end 73.013062 -221.340172)
		(width 0.20066)
		(layer "F.Cu")
		(net "M_A_CPU1_SB_DQ<14>")
	)
	(segment
		(start 62.547246 -216.441528)
		(end 62.649862 -216.338912)
		(width 0.20066)
		(layer "F.Cu")
		(net "M_A_CPU1_SB_DQ<14>")
	)
	(segment
		(start 62.649862 -216.338912)
		(end 62.649862 -215.99271)
		(width 0.20066)
		(layer "F.Cu")
		(net "M_A_CPU1_SB_DQ<14>")
	)
	(segment
		(start 73.722992 -226.991418)
		(end 73.722992 -226.265486)
		(width 0.20066)
		(layer "F.Cu")
		(net "M_A_CPU1_SB_DQ<14>")
	)
	(segment
		(start 62.147958 -216.441528)
		(end 62.547246 -216.441528)
		(width 0.20066)
		(layer "F.Cu")
		(net "M_A_CPU1_SB_DQ<14>")
	)
	(segment
		(start 87.202264 -234.689904)
		(end 86.500716 -234.285028)
		(width 0.088646)
		(layer "F.Cu")
		(net "M_A_CPU1_SB_DQ<14>")
	)
	(segment
		(start 75.14209 -226.064826)
		(end 74.634852 -226.064826)
		(width 0.20066)
		(layer "F.Cu")
		(net "M_A_CPU1_SB_DQ<14>")
	)
	(segment
		(start 73.722992 -226.265486)
		(end 73.522332 -226.064826)
		(width 0.20066)
		(layer "F.Cu")
		(net "M_A_CPU1_SB_DQ<14>")
	)
	(segment
		(start 75.335892 -226.708208)
		(end 75.335892 -226.258628)
		(width 0.20066)
		(layer "F.Cu")
		(net "M_A_CPU1_SB_DQ<14>")
	)
	(segment
		(start 85.104478 -234.277154)
		(end 84.848446 -234.533186)
		(width 0.088646)
		(layer "F.Cu")
		(net "M_A_CPU1_SB_DQ<14>")
	)
	(segment
		(start 62.649862 -215.99271)
		(end 62.827916 -215.814656)
		(width 0.20066)
		(layer "F.Cu")
		(net "M_A_CPU1_SB_DQ<14>")
	)
	(segment
		(start 59.833002 -216.441528)
		(end 60.088018 -216.441528)
		(width 0.101854)
		(layer "F.Cu")
		(net "M_A_CPU1_SB_DQ<14>")
	)
	(segment
		(start 76.332842 -227.166678)
		(end 76.108052 -226.941888)
		(width 0.20066)
		(layer "F.Cu")
		(net "M_A_CPU1_SB_DQ<14>")
	)
	(segment
		(start 74.634852 -226.064826)
		(end 74.434192 -226.265486)
		(width 0.20066)
		(layer "F.Cu")
		(net "M_A_CPU1_SB_DQ<14>")
	)
	(segment
		(start 61.87567 -216.441528)
		(end 62.147958 -216.441528)
		(width 0.101854)
		(layer "F.Cu")
		(net "M_A_CPU1_SB_DQ<14>")
	)
	(segment
		(start 67.079622 -215.406732)
		(end 66.567558 -215.406732)
		(width 0.20066)
		(layer "F.Cu")
		(net "M_A_CPU1_SB_DQ<14>")
	)
	(segment
		(start 83.85937 -234.170474)
		(end 83.521296 -234.170474)
		(width 0.088646)
		(layer "F.Cu")
		(net "M_A_CPU1_SB_DQ<14>")
	)
	(segment
		(start 63.34506 -216.016586)
		(end 65.047114 -216.016586)
		(width 0.20066)
		(layer "F.Cu")
		(net "M_A_CPU1_SB_DQ<14>")
	)
	(segment
		(start 76.689204 -227.52304)
		(end 76.332842 -227.166678)
		(width 0.1016)
		(layer "F.Cu")
		(net "M_A_CPU1_SB_DQ<14>")
	)
	(segment
		(start 74.434192 -226.265486)
		(end 74.434192 -226.991418)
		(width 0.20066)
		(layer "F.Cu")
		(net "M_A_CPU1_SB_DQ<14>")
	)
	(segment
		(start 59.822842 -216.451688)
		(end 59.833002 -216.441528)
		(width 0.101854)
		(layer "F.Cu")
		(net "M_A_CPU1_SB_DQ<14>")
	)
	(segment
		(start 74.434192 -226.991418)
		(end 74.233532 -227.192078)
		(width 0.20066)
		(layer "F.Cu")
		(net "M_A_CPU1_SB_DQ<14>")
	)
	(arc
		(start 85.560916 -234.285028)
		(mid 85.333729 -234.222044)
		(end 85.104478 -234.277154)
		(width 0.088646)
		(layer "F.Cu")
		(net "M_A_CPU1_SB_DQ<14>")
	)
	(arc
		(start 86.500716 -234.285028)
		(mid 86.265766 -234.222102)
		(end 86.030816 -234.285028)
		(width 0.088646)
		(layer "F.Cu")
		(net "M_A_CPU1_SB_DQ<14>")
	)
	(arc
		(start 87.205312 -234.69219)
		(mid 87.203861 -234.69095)
		(end 87.202264 -234.689904)
		(width 0.088646)
		(layer "F.Cu")
		(net "M_A_CPU1_SB_DQ<14>")
	)
	(arc
		(start 86.030816 -234.285028)
		(mid 85.795866 -234.347988)
		(end 85.560916 -234.285028)
		(width 0.088646)
		(layer "F.Cu")
		(net "M_A_CPU1_SB_DQ<14>")
	)
	(segment
		(start 56.393334 -214.74176)
		(end 58.373518 -214.74176)
		(width 0.1016)
		(layer "F.Cu")
		(net "M_A_CPU1_SB_DQ<13>")
	)
	(segment
		(start 54.79034 -215.417654)
		(end 55.331868 -215.417654)
		(width 0.20066)
		(layer "F.Cu")
		(net "M_A_CPU1_SB_DQ<13>")
	)
	(segment
		(start 54.539388 -215.166702)
		(end 54.79034 -215.417654)
		(width 0.20066)
		(layer "F.Cu")
		(net "M_A_CPU1_SB_DQ<13>")
	)
	(segment
		(start 66.186812 -214.73287)
		(end 66.155824 -214.73287)
		(width 0.101854)
		(layer "F.Cu")
		(net "M_A_CPU1_SB_DQ<13>")
	)
	(segment
		(start 66.147188 -214.741506)
		(end 64.185292 -214.741506)
		(width 0.1016)
		(layer "F.Cu")
		(net "M_A_CPU1_SB_DQ<13>")
	)
	(segment
		(start 85.795866 -233.87812)
		(end 85.245956 -233.671364)
		(width 0.088646)
		(layer "F.Cu")
		(net "M_A_CPU1_SB_DQ<13>")
	)
	(segment
		(start 84.703666 -233.489246)
		(end 84.188046 -233.489246)
		(width 0.088646)
		(layer "F.Cu")
		(net "M_A_CPU1_SB_DQ<13>")
	)
	(segment
		(start 63.263526 -214.73033)
		(end 62.827154 -215.166702)
		(width 0.20066)
		(layer "F.Cu")
		(net "M_A_CPU1_SB_DQ<13>")
	)
	(segment
		(start 55.331868 -215.417654)
		(end 55.607712 -215.14181)
		(width 0.20066)
		(layer "F.Cu")
		(net "M_A_CPU1_SB_DQ<13>")
	)
	(segment
		(start 83.953096 -233.532426)
		(end 82.963258 -233.532426)
		(width 0.1016)
		(layer "F.Cu")
		(net "M_A_CPU1_SB_DQ<13>")
	)
	(segment
		(start 77.014324 -226.938586)
		(end 76.44003 -226.364292)
		(width 0.1016)
		(layer "F.Cu")
		(net "M_A_CPU1_SB_DQ<13>")
	)
	(segment
		(start 53.403246 -215.166702)
		(end 54.539388 -215.166702)
		(width 0.20066)
		(layer "F.Cu")
		(net "M_A_CPU1_SB_DQ<13>")
	)
	(segment
		(start 67.327018 -214.73287)
		(end 66.186812 -214.73287)
		(width 0.20066)
		(layer "F.Cu")
		(net "M_A_CPU1_SB_DQ<13>")
	)
	(segment
		(start 59.268868 -215.166702)
		(end 60.947046 -215.166702)
		(width 0.20066)
		(layer "F.Cu")
		(net "M_A_CPU1_SB_DQ<13>")
	)
	(segment
		(start 63.994284 -214.73033)
		(end 63.977012 -214.73033)
		(width 0.101854)
		(layer "F.Cu")
		(net "M_A_CPU1_SB_DQ<13>")
	)
	(segment
		(start 64.00546 -214.741506)
		(end 63.994284 -214.73033)
		(width 0.101854)
		(layer "F.Cu")
		(net "M_A_CPU1_SB_DQ<13>")
	)
	(segment
		(start 82.963258 -233.532426)
		(end 77.158596 -227.727764)
		(width 0.1016)
		(layer "F.Cu")
		(net "M_A_CPU1_SB_DQ<13>")
	)
	(segment
		(start 58.704226 -214.74176)
		(end 58.843926 -214.74176)
		(width 0.20066)
		(layer "F.Cu")
		(net "M_A_CPU1_SB_DQ<13>")
	)
	(segment
		(start 55.607712 -214.896446)
		(end 55.776622 -214.727536)
		(width 0.20066)
		(layer "F.Cu")
		(net "M_A_CPU1_SB_DQ<13>")
	)
	(segment
		(start 76.44003 -226.36353)
		(end 75.473306 -225.396806)
		(width 0.20066)
		(layer "F.Cu")
		(net "M_A_CPU1_SB_DQ<13>")
	)
	(segment
		(start 84.854796 -233.50347)
		(end 84.703666 -233.489246)
		(width 0.088646)
		(layer "F.Cu")
		(net "M_A_CPU1_SB_DQ<13>")
	)
	(segment
		(start 74.24166 -225.396806)
		(end 73.695814 -224.85096)
		(width 0.20066)
		(layer "F.Cu")
		(net "M_A_CPU1_SB_DQ<13>")
	)
	(segment
		(start 58.843926 -214.74176)
		(end 59.268868 -215.166702)
		(width 0.20066)
		(layer "F.Cu")
		(net "M_A_CPU1_SB_DQ<13>")
	)
	(segment
		(start 85.245956 -233.671364)
		(end 85.041994 -233.553762)
		(width 0.088646)
		(layer "F.Cu")
		(net "M_A_CPU1_SB_DQ<13>")
	)
	(segment
		(start 58.373518 -214.74176)
		(end 58.704226 -214.74176)
		(width 0.101854)
		(layer "F.Cu")
		(net "M_A_CPU1_SB_DQ<13>")
	)
	(segment
		(start 84.019898 -233.532426)
		(end 83.953096 -233.532426)
		(width 0.088646)
		(layer "F.Cu")
		(net "M_A_CPU1_SB_DQ<13>")
	)
	(segment
		(start 64.185292 -214.741506)
		(end 64.00546 -214.741506)
		(width 0.101854)
		(layer "F.Cu")
		(net "M_A_CPU1_SB_DQ<13>")
	)
	(segment
		(start 77.014324 -227.583492)
		(end 77.014324 -226.938586)
		(width 0.1016)
		(layer "F.Cu")
		(net "M_A_CPU1_SB_DQ<13>")
	)
	(segment
		(start 73.695814 -221.101666)
		(end 67.327018 -214.73287)
		(width 0.20066)
		(layer "F.Cu")
		(net "M_A_CPU1_SB_DQ<13>")
	)
	(segment
		(start 62.827154 -215.166702)
		(end 60.947046 -215.166702)
		(width 0.20066)
		(layer "F.Cu")
		(net "M_A_CPU1_SB_DQ<13>")
	)
	(segment
		(start 76.44003 -226.364292)
		(end 76.44003 -226.36353)
		(width 0.20066)
		(layer "F.Cu")
		(net "M_A_CPU1_SB_DQ<13>")
	)
	(segment
		(start 73.695814 -224.85096)
		(end 73.695814 -221.101666)
		(width 0.20066)
		(layer "F.Cu")
		(net "M_A_CPU1_SB_DQ<13>")
	)
	(segment
		(start 84.188046 -233.489246)
		(end 84.019898 -233.532426)
		(width 0.088646)
		(layer "F.Cu")
		(net "M_A_CPU1_SB_DQ<13>")
	)
	(segment
		(start 77.158596 -227.727764)
		(end 77.014324 -227.583492)
		(width 0.101854)
		(layer "F.Cu")
		(net "M_A_CPU1_SB_DQ<13>")
	)
	(segment
		(start 55.607712 -215.14181)
		(end 55.607712 -214.896446)
		(width 0.20066)
		(layer "F.Cu")
		(net "M_A_CPU1_SB_DQ<13>")
	)
	(segment
		(start 56.37911 -214.727536)
		(end 56.393334 -214.74176)
		(width 0.1016)
		(layer "F.Cu")
		(net "M_A_CPU1_SB_DQ<13>")
	)
	(segment
		(start 75.473306 -225.396806)
		(end 74.24166 -225.396806)
		(width 0.20066)
		(layer "F.Cu")
		(net "M_A_CPU1_SB_DQ<13>")
	)
	(segment
		(start 66.155824 -214.73287)
		(end 66.147188 -214.741506)
		(width 0.101854)
		(layer "F.Cu")
		(net "M_A_CPU1_SB_DQ<13>")
	)
	(segment
		(start 55.776622 -214.727536)
		(end 56.37911 -214.727536)
		(width 0.20066)
		(layer "F.Cu")
		(net "M_A_CPU1_SB_DQ<13>")
	)
	(segment
		(start 63.977012 -214.73033)
		(end 63.263526 -214.73033)
		(width 0.20066)
		(layer "F.Cu")
		(net "M_A_CPU1_SB_DQ<13>")
	)
	(arc
		(start 85.041994 -233.553762)
		(mid 84.951702 -233.51631)
		(end 84.854796 -233.50347)
		(width 0.088646)
		(layer "F.Cu")
		(net "M_A_CPU1_SB_DQ<13>")
	)
	(segment
		(start 58.373518 -216.441782)
		(end 58.704226 -216.441782)
		(width 0.101854)
		(layer "F.Cu")
		(net "M_A_CPU1_SB_DQ<12>")
	)
	(segment
		(start 72.3519 -221.621858)
		(end 68.233544 -217.503502)
		(width 0.20066)
		(layer "F.Cu")
		(net "M_A_CPU1_SB_DQ<12>")
	)
	(segment
		(start 76.35367 -227.842572)
		(end 76.332842 -227.842572)
		(width 0.1016)
		(layer "F.Cu")
		(net "M_A_CPU1_SB_DQ<12>")
	)
	(segment
		(start 72.3519 -226.747578)
		(end 72.3519 -221.621858)
		(width 0.20066)
		(layer "F.Cu")
		(net "M_A_CPU1_SB_DQ<12>")
	)
	(segment
		(start 83.521296 -234.475274)
		(end 83.043268 -234.475274)
		(width 0.1016)
		(layer "F.Cu")
		(net "M_A_CPU1_SB_DQ<12>")
	)
	(segment
		(start 67.458844 -217.048334)
		(end 67.458844 -216.728802)
		(width 0.20066)
		(layer "F.Cu")
		(net "M_A_CPU1_SB_DQ<12>")
	)
	(segment
		(start 73.446894 -227.842572)
		(end 72.3519 -226.747578)
		(width 0.20066)
		(layer "F.Cu")
		(net "M_A_CPU1_SB_DQ<12>")
	)
	(segment
		(start 58.704226 -216.441782)
		(end 58.932064 -216.441782)
		(width 0.20066)
		(layer "F.Cu")
		(net "M_A_CPU1_SB_DQ<12>")
	)
	(segment
		(start 85.325712 -234.69219)
		(end 85.291422 -234.72648)
		(width 0.088646)
		(layer "F.Cu")
		(net "M_A_CPU1_SB_DQ<12>")
	)
	(segment
		(start 83.86572 -234.475274)
		(end 83.521296 -234.475274)
		(width 0.088646)
		(layer "F.Cu")
		(net "M_A_CPU1_SB_DQ<12>")
	)
	(segment
		(start 55.607712 -216.658952)
		(end 55.836566 -216.430098)
		(width 0.20066)
		(layer "F.Cu")
		(net "M_A_CPU1_SB_DQ<12>")
	)
	(segment
		(start 67.458844 -216.728802)
		(end 67.162426 -216.432384)
		(width 0.20066)
		(layer "F.Cu")
		(net "M_A_CPU1_SB_DQ<12>")
	)
	(segment
		(start 54.97195 -217.160094)
		(end 55.332122 -217.160094)
		(width 0.20066)
		(layer "F.Cu")
		(net "M_A_CPU1_SB_DQ<12>")
	)
	(segment
		(start 63.977012 -216.43213)
		(end 63.261748 -216.43213)
		(width 0.20066)
		(layer "F.Cu")
		(net "M_A_CPU1_SB_DQ<12>")
	)
	(segment
		(start 55.607712 -216.884504)
		(end 55.607712 -216.658952)
		(width 0.20066)
		(layer "F.Cu")
		(net "M_A_CPU1_SB_DQ<12>")
	)
	(segment
		(start 85.291422 -234.72648)
		(end 84.116926 -234.72648)
		(width 0.088646)
		(layer "F.Cu")
		(net "M_A_CPU1_SB_DQ<12>")
	)
	(segment
		(start 64.185292 -216.441528)
		(end 63.988696 -216.441528)
		(width 0.101854)
		(layer "F.Cu")
		(net "M_A_CPU1_SB_DQ<12>")
	)
	(segment
		(start 83.043268 -234.475274)
		(end 76.613766 -228.045772)
		(width 0.1016)
		(layer "F.Cu")
		(net "M_A_CPU1_SB_DQ<12>")
	)
	(segment
		(start 53.403246 -216.866724)
		(end 54.67858 -216.866724)
		(width 0.20066)
		(layer "F.Cu")
		(net "M_A_CPU1_SB_DQ<12>")
	)
	(segment
		(start 63.261748 -216.43213)
		(end 62.827154 -216.866724)
		(width 0.20066)
		(layer "F.Cu")
		(net "M_A_CPU1_SB_DQ<12>")
	)
	(segment
		(start 56.387238 -216.430098)
		(end 56.398922 -216.441782)
		(width 0.1016)
		(layer "F.Cu")
		(net "M_A_CPU1_SB_DQ<12>")
	)
	(segment
		(start 55.332122 -217.160094)
		(end 55.607712 -216.884504)
		(width 0.20066)
		(layer "F.Cu")
		(net "M_A_CPU1_SB_DQ<12>")
	)
	(segment
		(start 67.914012 -217.503502)
		(end 67.458844 -217.048334)
		(width 0.20066)
		(layer "F.Cu")
		(net "M_A_CPU1_SB_DQ<12>")
	)
	(segment
		(start 62.827154 -216.866724)
		(end 60.947046 -216.866724)
		(width 0.20066)
		(layer "F.Cu")
		(net "M_A_CPU1_SB_DQ<12>")
	)
	(segment
		(start 56.37911 -216.430098)
		(end 56.387238 -216.430098)
		(width 0.101854)
		(layer "F.Cu")
		(net "M_A_CPU1_SB_DQ<12>")
	)
	(segment
		(start 63.979298 -216.43213)
		(end 63.977012 -216.43213)
		(width 0.101854)
		(layer "F.Cu")
		(net "M_A_CPU1_SB_DQ<12>")
	)
	(segment
		(start 63.988696 -216.441528)
		(end 63.979298 -216.43213)
		(width 0.101854)
		(layer "F.Cu")
		(net "M_A_CPU1_SB_DQ<12>")
	)
	(segment
		(start 67.162426 -216.432384)
		(end 66.186812 -216.432384)
		(width 0.20066)
		(layer "F.Cu")
		(net "M_A_CPU1_SB_DQ<12>")
	)
	(segment
		(start 76.332842 -227.842572)
		(end 73.446894 -227.842572)
		(width 0.20066)
		(layer "F.Cu")
		(net "M_A_CPU1_SB_DQ<12>")
	)
	(segment
		(start 55.836566 -216.430098)
		(end 56.37911 -216.430098)
		(width 0.20066)
		(layer "F.Cu")
		(net "M_A_CPU1_SB_DQ<12>")
	)
	(segment
		(start 56.398922 -216.441782)
		(end 58.373518 -216.441782)
		(width 0.1016)
		(layer "F.Cu")
		(net "M_A_CPU1_SB_DQ<12>")
	)
	(segment
		(start 76.613766 -228.045772)
		(end 76.55687 -228.045772)
		(width 0.1016)
		(layer "F.Cu")
		(net "M_A_CPU1_SB_DQ<12>")
	)
	(segment
		(start 84.116926 -234.72648)
		(end 83.86572 -234.475274)
		(width 0.088646)
		(layer "F.Cu")
		(net "M_A_CPU1_SB_DQ<12>")
	)
	(segment
		(start 66.177668 -216.441528)
		(end 64.185292 -216.441528)
		(width 0.1016)
		(layer "F.Cu")
		(net "M_A_CPU1_SB_DQ<12>")
	)
	(segment
		(start 58.932064 -216.441782)
		(end 59.357006 -216.866724)
		(width 0.20066)
		(layer "F.Cu")
		(net "M_A_CPU1_SB_DQ<12>")
	)
	(segment
		(start 54.67858 -216.866724)
		(end 54.97195 -217.160094)
		(width 0.20066)
		(layer "F.Cu")
		(net "M_A_CPU1_SB_DQ<12>")
	)
	(segment
		(start 66.186812 -216.432384)
		(end 66.177668 -216.441528)
		(width 0.101854)
		(layer "F.Cu")
		(net "M_A_CPU1_SB_DQ<12>")
	)
	(segment
		(start 68.233544 -217.503502)
		(end 67.914012 -217.503502)
		(width 0.20066)
		(layer "F.Cu")
		(net "M_A_CPU1_SB_DQ<12>")
	)
	(segment
		(start 59.357006 -216.866724)
		(end 60.947046 -216.866724)
		(width 0.20066)
		(layer "F.Cu")
		(net "M_A_CPU1_SB_DQ<12>")
	)
	(segment
		(start 76.55687 -228.045772)
		(end 76.35367 -227.842572)
		(width 0.1016)
		(layer "F.Cu")
		(net "M_A_CPU1_SB_DQ<12>")
	)
	(segment
		(start 60.096654 -220.69171)
		(end 61.863986 -220.69171)
		(width 0.1016)
		(layer "F.Cu")
		(net "M_A_CPU1_SB_DQ<11>")
	)
	(segment
		(start 69.447664 -226.08413)
		(end 69.247004 -225.88347)
		(width 0.20066)
		(layer "F.Cu")
		(net "M_A_CPU1_SB_DQ<11>")
	)
	(segment
		(start 87.200232 -235.88853)
		(end 87.018622 -235.994956)
		(width 0.088646)
		(layer "F.Cu")
		(net "M_A_CPU1_SB_DQ<11>")
	)
	(segment
		(start 69.247004 -226.59467)
		(end 69.447664 -226.39401)
		(width 0.20066)
		(layer "F.Cu")
		(net "M_A_CPU1_SB_DQ<11>")
	)
	(segment
		(start 69.447664 -224.66173)
		(end 69.247004 -224.46107)
		(width 0.20066)
		(layer "F.Cu")
		(net "M_A_CPU1_SB_DQ<11>")
	)
	(segment
		(start 69.247004 -225.88347)
		(end 68.900548 -225.88347)
		(width 0.20066)
		(layer "F.Cu")
		(net "M_A_CPU1_SB_DQ<11>")
	)
	(segment
		(start 85.518752 -235.917486)
		(end 85.384386 -235.917486)
		(width 0.088646)
		(layer "F.Cu")
		(net "M_A_CPU1_SB_DQ<11>")
	)
	(segment
		(start 64.076072 -220.266768)
		(end 65.047114 -220.266768)
		(width 0.20066)
		(layer "F.Cu")
		(net "M_A_CPU1_SB_DQ<11>")
	)
	(segment
		(start 76.332842 -230.831136)
		(end 72.273668 -230.831136)
		(width 0.20066)
		(layer "F.Cu")
		(net "M_A_CPU1_SB_DQ<11>")
	)
	(segment
		(start 82.48142 -236.069886)
		(end 77.24267 -230.831136)
		(width 0.1016)
		(layer "F.Cu")
		(net "M_A_CPU1_SB_DQ<11>")
	)
	(segment
		(start 72.273668 -230.831136)
		(end 69.447664 -228.005132)
		(width 0.20066)
		(layer "F.Cu")
		(net "M_A_CPU1_SB_DQ<11>")
	)
	(segment
		(start 84.938108 -236.069886)
		(end 83.521296 -236.069886)
		(width 0.088646)
		(layer "F.Cu")
		(net "M_A_CPU1_SB_DQ<11>")
	)
	(segment
		(start 62.706758 -220.3704)
		(end 62.904624 -220.172534)
		(width 0.20066)
		(layer "F.Cu")
		(net "M_A_CPU1_SB_DQ<11>")
	)
	(segment
		(start 62.706758 -220.564964)
		(end 62.706758 -220.3704)
		(width 0.20066)
		(layer "F.Cu")
		(net "M_A_CPU1_SB_DQ<11>")
	)
	(segment
		(start 69.247004 -224.46107)
		(end 68.900548 -224.46107)
		(width 0.20066)
		(layer "F.Cu")
		(net "M_A_CPU1_SB_DQ<11>")
	)
	(segment
		(start 69.247004 -227.30587)
		(end 68.900548 -227.30587)
		(width 0.20066)
		(layer "F.Cu")
		(net "M_A_CPU1_SB_DQ<11>")
	)
	(segment
		(start 60.01131 -220.777054)
		(end 60.096654 -220.69171)
		(width 0.1016)
		(layer "F.Cu")
		(net "M_A_CPU1_SB_DQ<11>")
	)
	(segment
		(start 67.188842 -220.517212)
		(end 66.1035 -220.517212)
		(width 0.20066)
		(layer "F.Cu")
		(net "M_A_CPU1_SB_DQ<11>")
	)
	(segment
		(start 69.447664 -227.50653)
		(end 69.247004 -227.30587)
		(width 0.20066)
		(layer "F.Cu")
		(net "M_A_CPU1_SB_DQ<11>")
	)
	(segment
		(start 86.452964 -235.995464)
		(end 86.310978 -235.913422)
		(width 0.088646)
		(layer "F.Cu")
		(net "M_A_CPU1_SB_DQ<11>")
	)
	(segment
		(start 58.932318 -220.266768)
		(end 59.442604 -220.777054)
		(width 0.20066)
		(layer "F.Cu")
		(net "M_A_CPU1_SB_DQ<11>")
	)
	(segment
		(start 62.554612 -220.71711)
		(end 62.706758 -220.564964)
		(width 0.20066)
		(layer "F.Cu")
		(net "M_A_CPU1_SB_DQ<11>")
	)
	(segment
		(start 69.447664 -222.776034)
		(end 67.188842 -220.517212)
		(width 0.20066)
		(layer "F.Cu")
		(net "M_A_CPU1_SB_DQ<11>")
	)
	(segment
		(start 85.522816 -235.913422)
		(end 85.518752 -235.917486)
		(width 0.088646)
		(layer "F.Cu")
		(net "M_A_CPU1_SB_DQ<11>")
	)
	(segment
		(start 69.447664 -224.97161)
		(end 69.447664 -224.66173)
		(width 0.20066)
		(layer "F.Cu")
		(net "M_A_CPU1_SB_DQ<11>")
	)
	(segment
		(start 59.442604 -220.777054)
		(end 59.822842 -220.777054)
		(width 0.20066)
		(layer "F.Cu")
		(net "M_A_CPU1_SB_DQ<11>")
	)
	(segment
		(start 63.937388 -220.405452)
		(end 64.076072 -220.266768)
		(width 0.20066)
		(layer "F.Cu")
		(net "M_A_CPU1_SB_DQ<11>")
	)
	(segment
		(start 69.447664 -223.54921)
		(end 69.447664 -222.776034)
		(width 0.20066)
		(layer "F.Cu")
		(net "M_A_CPU1_SB_DQ<11>")
	)
	(segment
		(start 69.447664 -226.39401)
		(end 69.447664 -226.08413)
		(width 0.20066)
		(layer "F.Cu")
		(net "M_A_CPU1_SB_DQ<11>")
	)
	(segment
		(start 69.247004 -223.74987)
		(end 69.447664 -223.54921)
		(width 0.20066)
		(layer "F.Cu")
		(net "M_A_CPU1_SB_DQ<11>")
	)
	(segment
		(start 65.853056 -220.266768)
		(end 65.047114 -220.266768)
		(width 0.20066)
		(layer "F.Cu")
		(net "M_A_CPU1_SB_DQ<11>")
	)
	(segment
		(start 68.900548 -225.88347)
		(end 68.699888 -225.68281)
		(width 0.20066)
		(layer "F.Cu")
		(net "M_A_CPU1_SB_DQ<11>")
	)
	(segment
		(start 68.699888 -227.10521)
		(end 68.699888 -226.79533)
		(width 0.20066)
		(layer "F.Cu")
		(net "M_A_CPU1_SB_DQ<11>")
	)
	(segment
		(start 86.310978 -235.913422)
		(end 85.522816 -235.913422)
		(width 0.088646)
		(layer "F.Cu")
		(net "M_A_CPU1_SB_DQ<11>")
	)
	(segment
		(start 68.699888 -225.68281)
		(end 68.699888 -225.37293)
		(width 0.20066)
		(layer "F.Cu")
		(net "M_A_CPU1_SB_DQ<11>")
	)
	(segment
		(start 87.008208 -236.001052)
		(end 87.007192 -236.001814)
		(width 0.088646)
		(layer "F.Cu")
		(net "M_A_CPU1_SB_DQ<11>")
	)
	(segment
		(start 63.472314 -220.405452)
		(end 63.937388 -220.405452)
		(width 0.20066)
		(layer "F.Cu")
		(net "M_A_CPU1_SB_DQ<11>")
	)
	(segment
		(start 63.239396 -220.172534)
		(end 63.472314 -220.405452)
		(width 0.20066)
		(layer "F.Cu")
		(net "M_A_CPU1_SB_DQ<11>")
	)
	(segment
		(start 68.900548 -224.46107)
		(end 68.699888 -224.26041)
		(width 0.20066)
		(layer "F.Cu")
		(net "M_A_CPU1_SB_DQ<11>")
	)
	(segment
		(start 66.1035 -220.517212)
		(end 65.853056 -220.266768)
		(width 0.20066)
		(layer "F.Cu")
		(net "M_A_CPU1_SB_DQ<11>")
	)
	(segment
		(start 87.360506 -236.050836)
		(end 87.331042 -235.942124)
		(width 0.088646)
		(layer "F.Cu")
		(net "M_A_CPU1_SB_DQ<11>")
	)
	(segment
		(start 57.503314 -220.266768)
		(end 58.932318 -220.266768)
		(width 0.20066)
		(layer "F.Cu")
		(net "M_A_CPU1_SB_DQ<11>")
	)
	(segment
		(start 62.904624 -220.172534)
		(end 63.239396 -220.172534)
		(width 0.20066)
		(layer "F.Cu")
		(net "M_A_CPU1_SB_DQ<11>")
	)
	(segment
		(start 85.174836 -235.973874)
		(end 85.137244 -235.995464)
		(width 0.088646)
		(layer "F.Cu")
		(net "M_A_CPU1_SB_DQ<11>")
	)
	(segment
		(start 69.247004 -225.17227)
		(end 69.447664 -224.97161)
		(width 0.20066)
		(layer "F.Cu")
		(net "M_A_CPU1_SB_DQ<11>")
	)
	(segment
		(start 87.205312 -236.319822)
		(end 87.360506 -236.050836)
		(width 0.088646)
		(layer "F.Cu")
		(net "M_A_CPU1_SB_DQ<11>")
	)
	(segment
		(start 59.822842 -220.777054)
		(end 59.887612 -220.777054)
		(width 0.101854)
		(layer "F.Cu")
		(net "M_A_CPU1_SB_DQ<11>")
	)
	(segment
		(start 62.147958 -220.71711)
		(end 62.554612 -220.71711)
		(width 0.20066)
		(layer "F.Cu")
		(net "M_A_CPU1_SB_DQ<11>")
	)
	(segment
		(start 68.900548 -223.74987)
		(end 69.247004 -223.74987)
		(width 0.20066)
		(layer "F.Cu")
		(net "M_A_CPU1_SB_DQ<11>")
	)
	(segment
		(start 68.900548 -225.17227)
		(end 69.247004 -225.17227)
		(width 0.20066)
		(layer "F.Cu")
		(net "M_A_CPU1_SB_DQ<11>")
	)
	(segment
		(start 61.863986 -220.69171)
		(end 61.889386 -220.71711)
		(width 0.1016)
		(layer "F.Cu")
		(net "M_A_CPU1_SB_DQ<11>")
	)
	(segment
		(start 59.887612 -220.777054)
		(end 60.01131 -220.777054)
		(width 0.1016)
		(layer "F.Cu")
		(net "M_A_CPU1_SB_DQ<11>")
	)
	(segment
		(start 68.699888 -225.37293)
		(end 68.900548 -225.17227)
		(width 0.20066)
		(layer "F.Cu")
		(net "M_A_CPU1_SB_DQ<11>")
	)
	(segment
		(start 68.699888 -223.95053)
		(end 68.900548 -223.74987)
		(width 0.20066)
		(layer "F.Cu")
		(net "M_A_CPU1_SB_DQ<11>")
	)
	(segment
		(start 68.699888 -224.26041)
		(end 68.699888 -223.95053)
		(width 0.20066)
		(layer "F.Cu")
		(net "M_A_CPU1_SB_DQ<11>")
	)
	(segment
		(start 68.900548 -227.30587)
		(end 68.699888 -227.10521)
		(width 0.20066)
		(layer "F.Cu")
		(net "M_A_CPU1_SB_DQ<11>")
	)
	(segment
		(start 68.900548 -226.59467)
		(end 69.247004 -226.59467)
		(width 0.20066)
		(layer "F.Cu")
		(net "M_A_CPU1_SB_DQ<11>")
	)
	(segment
		(start 77.24267 -230.831136)
		(end 76.332842 -230.831136)
		(width 0.1016)
		(layer "F.Cu")
		(net "M_A_CPU1_SB_DQ<11>")
	)
	(segment
		(start 68.699888 -226.79533)
		(end 68.900548 -226.59467)
		(width 0.20066)
		(layer "F.Cu")
		(net "M_A_CPU1_SB_DQ<11>")
	)
	(segment
		(start 69.447664 -228.005132)
		(end 69.447664 -227.50653)
		(width 0.20066)
		(layer "F.Cu")
		(net "M_A_CPU1_SB_DQ<11>")
	)
	(segment
		(start 61.889386 -220.71711)
		(end 62.147958 -220.71711)
		(width 0.101854)
		(layer "F.Cu")
		(net "M_A_CPU1_SB_DQ<11>")
	)
	(segment
		(start 83.521296 -236.069886)
		(end 82.48142 -236.069886)
		(width 0.1016)
		(layer "F.Cu")
		(net "M_A_CPU1_SB_DQ<11>")
	)
	(arc
		(start 87.331042 -235.942124)
		(mid 87.278896 -235.882966)
		(end 87.200232 -235.88853)
		(width 0.088646)
		(layer "F.Cu")
		(net "M_A_CPU1_SB_DQ<11>")
	)
	(arc
		(start 85.137244 -235.995464)
		(mid 85.069465 -236.030287)
		(end 84.99856 -236.058202)
		(width 0.088646)
		(layer "F.Cu")
		(net "M_A_CPU1_SB_DQ<11>")
	)
	(arc
		(start 87.018622 -235.994956)
		(mid 87.017099 -235.995847)
		(end 87.015574 -235.996734)
		(width 0.088646)
		(layer "F.Cu")
		(net "M_A_CPU1_SB_DQ<11>")
	)
	(arc
		(start 87.007192 -236.001814)
		(mid 86.729239 -236.071259)
		(end 86.452964 -235.995464)
		(width 0.088646)
		(layer "F.Cu")
		(net "M_A_CPU1_SB_DQ<11>")
	)
	(arc
		(start 84.962746 -236.0676)
		(mid 84.950481 -236.069323)
		(end 84.938108 -236.069886)
		(width 0.088646)
		(layer "F.Cu")
		(net "M_A_CPU1_SB_DQ<11>")
	)
	(arc
		(start 85.384386 -235.917486)
		(mid 85.275891 -235.931859)
		(end 85.174836 -235.973874)
		(width 0.088646)
		(layer "F.Cu")
		(net "M_A_CPU1_SB_DQ<11>")
	)
	(arc
		(start 87.014304 -235.997496)
		(mid 87.011262 -235.999284)
		(end 87.008208 -236.001052)
		(width 0.088646)
		(layer "F.Cu")
		(net "M_A_CPU1_SB_DQ<11>")
	)
	(arc
		(start 87.015574 -235.996734)
		(mid 87.014939 -235.997114)
		(end 87.014304 -235.997496)
		(width 0.088646)
		(layer "F.Cu")
		(net "M_A_CPU1_SB_DQ<11>")
	)
	(arc
		(start 84.99856 -236.058202)
		(mid 84.98081 -236.063497)
		(end 84.962746 -236.0676)
		(width 0.088646)
		(layer "F.Cu")
		(net "M_A_CPU1_SB_DQ<11>")
	)
	(segment
		(start 76.779628 -232.459276)
		(end 70.423024 -232.459276)
		(width 0.20066)
		(layer "F.Cu")
		(net "M_A_CPU1_SB_DQ<10>")
	)
	(segment
		(start 59.082178 -221.96679)
		(end 59.594496 -222.479108)
		(width 0.20066)
		(layer "F.Cu")
		(net "M_A_CPU1_SB_DQ<10>")
	)
	(segment
		(start 69.496178 -230.331518)
		(end 69.496178 -230.047546)
		(width 0.20066)
		(layer "F.Cu")
		(net "M_A_CPU1_SB_DQ<10>")
	)
	(segment
		(start 61.86424 -222.391732)
		(end 62.130178 -222.391732)
		(width 0.101854)
		(layer "F.Cu")
		(net "M_A_CPU1_SB_DQ<10>")
	)
	(segment
		(start 70.043548 -232.0798)
		(end 70.043548 -231.795828)
		(width 0.20066)
		(layer "F.Cu")
		(net "M_A_CPU1_SB_DQ<10>")
	)
	(segment
		(start 69.999098 -230.834438)
		(end 69.540628 -231.292908)
		(width 0.20066)
		(layer "F.Cu")
		(net "M_A_CPU1_SB_DQ<10>")
	)
	(segment
		(start 70.28307 -230.834438)
		(end 69.999098 -230.834438)
		(width 0.20066)
		(layer "F.Cu")
		(net "M_A_CPU1_SB_DQ<10>")
	)
	(segment
		(start 60.02147 -222.479108)
		(end 60.098686 -222.401892)
		(width 0.101854)
		(layer "F.Cu")
		(net "M_A_CPU1_SB_DQ<10>")
	)
	(segment
		(start 83.95208 -236.529626)
		(end 83.80222 -236.679486)
		(width 0.088646)
		(layer "F.Cu")
		(net "M_A_CPU1_SB_DQ<10>")
	)
	(segment
		(start 77.68209 -232.13314)
		(end 77.248004 -232.13314)
		(width 0.1016)
		(layer "F.Cu")
		(net "M_A_CPU1_SB_DQ<10>")
	)
	(segment
		(start 67.35953 -229.395782)
		(end 67.35953 -222.497904)
		(width 0.20066)
		(layer "F.Cu")
		(net "M_A_CPU1_SB_DQ<10>")
	)
	(segment
		(start 68.993258 -229.828598)
		(end 68.534788 -230.287068)
		(width 0.20066)
		(layer "F.Cu")
		(net "M_A_CPU1_SB_DQ<10>")
	)
	(segment
		(start 69.496178 -230.047546)
		(end 69.27723 -229.828598)
		(width 0.20066)
		(layer "F.Cu")
		(net "M_A_CPU1_SB_DQ<10>")
	)
	(segment
		(start 62.130178 -222.391732)
		(end 62.147958 -222.409512)
		(width 0.101854)
		(layer "F.Cu")
		(net "M_A_CPU1_SB_DQ<10>")
	)
	(segment
		(start 62.417706 -222.409512)
		(end 62.590172 -222.237046)
		(width 0.20066)
		(layer "F.Cu")
		(net "M_A_CPU1_SB_DQ<10>")
	)
	(segment
		(start 60.132722 -222.391732)
		(end 61.86424 -222.391732)
		(width 0.1016)
		(layer "F.Cu")
		(net "M_A_CPU1_SB_DQ<10>")
	)
	(segment
		(start 77.105764 -232.13314)
		(end 76.779628 -232.459276)
		(width 0.20066)
		(layer "F.Cu")
		(net "M_A_CPU1_SB_DQ<10>")
	)
	(segment
		(start 70.502018 -231.053386)
		(end 70.28307 -230.834438)
		(width 0.20066)
		(layer "F.Cu")
		(net "M_A_CPU1_SB_DQ<10>")
	)
	(segment
		(start 70.043548 -231.795828)
		(end 70.502018 -231.337358)
		(width 0.20066)
		(layer "F.Cu")
		(net "M_A_CPU1_SB_DQ<10>")
	)
	(segment
		(start 83.521296 -236.679486)
		(end 82.228436 -236.679486)
		(width 0.1016)
		(layer "F.Cu")
		(net "M_A_CPU1_SB_DQ<10>")
	)
	(segment
		(start 60.098686 -222.401892)
		(end 60.132722 -222.391732)
		(width 0.1016)
		(layer "F.Cu")
		(net "M_A_CPU1_SB_DQ<10>")
	)
	(segment
		(start 63.264542 -221.96679)
		(end 65.047114 -221.96679)
		(width 0.20066)
		(layer "F.Cu")
		(net "M_A_CPU1_SB_DQ<10>")
	)
	(segment
		(start 70.502018 -231.337358)
		(end 70.502018 -231.053386)
		(width 0.20066)
		(layer "F.Cu")
		(net "M_A_CPU1_SB_DQ<10>")
	)
	(segment
		(start 70.423024 -232.459276)
		(end 70.043548 -232.0798)
		(width 0.20066)
		(layer "F.Cu")
		(net "M_A_CPU1_SB_DQ<10>")
	)
	(segment
		(start 62.590172 -222.237046)
		(end 62.590172 -221.990666)
		(width 0.20066)
		(layer "F.Cu")
		(net "M_A_CPU1_SB_DQ<10>")
	)
	(segment
		(start 67.35953 -222.497904)
		(end 66.828416 -221.96679)
		(width 0.20066)
		(layer "F.Cu")
		(net "M_A_CPU1_SB_DQ<10>")
	)
	(segment
		(start 69.037708 -231.07396)
		(end 69.037708 -230.789988)
		(width 0.20066)
		(layer "F.Cu")
		(net "M_A_CPU1_SB_DQ<10>")
	)
	(segment
		(start 77.248004 -232.13314)
		(end 77.105764 -232.13314)
		(width 0.20066)
		(layer "F.Cu")
		(net "M_A_CPU1_SB_DQ<10>")
	)
	(segment
		(start 82.228436 -236.679486)
		(end 77.68209 -232.13314)
		(width 0.1016)
		(layer "F.Cu")
		(net "M_A_CPU1_SB_DQ<10>")
	)
	(segment
		(start 62.590172 -221.990666)
		(end 62.796928 -221.78391)
		(width 0.20066)
		(layer "F.Cu")
		(net "M_A_CPU1_SB_DQ<10>")
	)
	(segment
		(start 69.27723 -229.828598)
		(end 68.993258 -229.828598)
		(width 0.20066)
		(layer "F.Cu")
		(net "M_A_CPU1_SB_DQ<10>")
	)
	(segment
		(start 86.735666 -237.133892)
		(end 86.030816 -236.726984)
		(width 0.088646)
		(layer "F.Cu")
		(net "M_A_CPU1_SB_DQ<10>")
	)
	(segment
		(start 62.147958 -222.409512)
		(end 62.417706 -222.409512)
		(width 0.20066)
		(layer "F.Cu")
		(net "M_A_CPU1_SB_DQ<10>")
	)
	(segment
		(start 57.503314 -221.96679)
		(end 59.082178 -221.96679)
		(width 0.20066)
		(layer "F.Cu")
		(net "M_A_CPU1_SB_DQ<10>")
	)
	(segment
		(start 84.688172 -236.529626)
		(end 83.95208 -236.529626)
		(width 0.088646)
		(layer "F.Cu")
		(net "M_A_CPU1_SB_DQ<10>")
	)
	(segment
		(start 69.540628 -231.292908)
		(end 69.256656 -231.292908)
		(width 0.20066)
		(layer "F.Cu")
		(net "M_A_CPU1_SB_DQ<10>")
	)
	(segment
		(start 69.037708 -230.789988)
		(end 69.496178 -230.331518)
		(width 0.20066)
		(layer "F.Cu")
		(net "M_A_CPU1_SB_DQ<10>")
	)
	(segment
		(start 85.560916 -236.726984)
		(end 85.424772 -236.726984)
		(width 0.088646)
		(layer "F.Cu")
		(net "M_A_CPU1_SB_DQ<10>")
	)
	(segment
		(start 69.256656 -231.292908)
		(end 69.037708 -231.07396)
		(width 0.20066)
		(layer "F.Cu")
		(net "M_A_CPU1_SB_DQ<10>")
	)
	(segment
		(start 59.594496 -222.479108)
		(end 59.822842 -222.479108)
		(width 0.20066)
		(layer "F.Cu")
		(net "M_A_CPU1_SB_DQ<10>")
	)
	(segment
		(start 66.828416 -221.96679)
		(end 65.047114 -221.96679)
		(width 0.20066)
		(layer "F.Cu")
		(net "M_A_CPU1_SB_DQ<10>")
	)
	(segment
		(start 63.081662 -221.78391)
		(end 63.264542 -221.96679)
		(width 0.20066)
		(layer "F.Cu")
		(net "M_A_CPU1_SB_DQ<10>")
	)
	(segment
		(start 59.822842 -222.479108)
		(end 60.02147 -222.479108)
		(width 0.101854)
		(layer "F.Cu")
		(net "M_A_CPU1_SB_DQ<10>")
	)
	(segment
		(start 62.796928 -221.78391)
		(end 63.081662 -221.78391)
		(width 0.20066)
		(layer "F.Cu")
		(net "M_A_CPU1_SB_DQ<10>")
	)
	(segment
		(start 68.250816 -230.287068)
		(end 67.35953 -229.395782)
		(width 0.20066)
		(layer "F.Cu")
		(net "M_A_CPU1_SB_DQ<10>")
	)
	(segment
		(start 83.80222 -236.679486)
		(end 83.521296 -236.679486)
		(width 0.088646)
		(layer "F.Cu")
		(net "M_A_CPU1_SB_DQ<10>")
	)
	(segment
		(start 68.534788 -230.287068)
		(end 68.250816 -230.287068)
		(width 0.20066)
		(layer "F.Cu")
		(net "M_A_CPU1_SB_DQ<10>")
	)
	(arc
		(start 85.424772 -236.726984)
		(mid 85.270675 -236.706705)
		(end 85.127084 -236.647228)
		(width 0.088646)
		(layer "F.Cu")
		(net "M_A_CPU1_SB_DQ<10>")
	)
	(arc
		(start 86.030816 -236.726984)
		(mid 85.795866 -236.664024)
		(end 85.560916 -236.726984)
		(width 0.088646)
		(layer "F.Cu")
		(net "M_A_CPU1_SB_DQ<10>")
	)
	(arc
		(start 85.127084 -236.647228)
		(mid 84.915365 -236.559559)
		(end 84.688172 -236.529626)
		(width 0.088646)
		(layer "F.Cu")
		(net "M_A_CPU1_SB_DQ<10>")
	)
	(segment
		(start 62.051946 -232.166668)
		(end 60.947046 -232.166668)
		(width 0.20066)
		(layer "F.Cu")
		(net "M_A_CPU1_SB_DQ<0>")
	)
	(segment
		(start 58.891678 -231.72547)
		(end 58.704226 -231.72547)
		(width 0.20066)
		(layer "F.Cu")
		(net "M_A_CPU1_SB_DQ<0>")
	)
	(segment
		(start 89.085166 -239.575086)
		(end 89.085166 -239.0394)
		(width 0.20066)
		(layer "F.Cu")
		(net "M_A_CPU1_SB_DQ<0>")
	)
	(segment
		(start 54.965092 -232.418382)
		(end 54.713378 -232.166668)
		(width 0.20066)
		(layer "F.Cu")
		(net "M_A_CPU1_SB_DQ<0>")
	)
	(segment
		(start 56.475376 -231.700324)
		(end 56.433212 -231.700324)
		(width 0.1016)
		(layer "F.Cu")
		(net "M_A_CPU1_SB_DQ<0>")
	)
	(segment
		(start 89.084912 -239.57534)
		(end 89.085166 -239.575086)
		(width 0.20066)
		(layer "F.Cu")
		(net "M_A_CPU1_SB_DQ<0>")
	)
	(segment
		(start 56.610758 -231.741726)
		(end 56.475376 -231.700324)
		(width 0.1016)
		(layer "F.Cu")
		(net "M_A_CPU1_SB_DQ<0>")
	)
	(segment
		(start 55.34914 -232.418382)
		(end 54.965092 -232.418382)
		(width 0.20066)
		(layer "F.Cu")
		(net "M_A_CPU1_SB_DQ<0>")
	)
	(segment
		(start 54.713378 -232.166668)
		(end 53.403246 -232.166668)
		(width 0.20066)
		(layer "F.Cu")
		(net "M_A_CPU1_SB_DQ<0>")
	)
	(segment
		(start 55.583328 -231.896158)
		(end 55.583328 -232.184194)
		(width 0.20066)
		(layer "F.Cu")
		(net "M_A_CPU1_SB_DQ<0>")
	)
	(segment
		(start 58.349134 -231.741726)
		(end 56.610758 -231.741726)
		(width 0.1016)
		(layer "F.Cu")
		(net "M_A_CPU1_SB_DQ<0>")
	)
	(segment
		(start 55.779162 -231.700324)
		(end 55.583328 -231.896158)
		(width 0.20066)
		(layer "F.Cu")
		(net "M_A_CPU1_SB_DQ<0>")
	)
	(segment
		(start 56.433212 -231.700324)
		(end 56.37911 -231.700324)
		(width 0.101854)
		(layer "F.Cu")
		(net "M_A_CPU1_SB_DQ<0>")
	)
	(segment
		(start 58.405776 -231.72547)
		(end 58.349134 -231.741726)
		(width 0.1016)
		(layer "F.Cu")
		(net "M_A_CPU1_SB_DQ<0>")
	)
	(segment
		(start 58.704226 -231.72547)
		(end 58.405776 -231.72547)
		(width 0.101854)
		(layer "F.Cu")
		(net "M_A_CPU1_SB_DQ<0>")
	)
	(segment
		(start 60.947046 -232.166668)
		(end 59.332876 -232.166668)
		(width 0.20066)
		(layer "F.Cu")
		(net "M_A_CPU1_SB_DQ<0>")
	)
	(segment
		(start 56.37911 -231.700324)
		(end 55.779162 -231.700324)
		(width 0.20066)
		(layer "F.Cu")
		(net "M_A_CPU1_SB_DQ<0>")
	)
	(segment
		(start 55.583328 -232.184194)
		(end 55.34914 -232.418382)
		(width 0.20066)
		(layer "F.Cu")
		(net "M_A_CPU1_SB_DQ<0>")
	)
	(segment
		(start 59.332876 -232.166668)
		(end 58.891678 -231.72547)
		(width 0.20066)
		(layer "F.Cu")
		(net "M_A_CPU1_SB_DQ<0>")
	)
	(segment
		(start 63.66129 -230.86441)
		(end 62.917578 -230.86441)
		(width 0.18288)
		(layer "In2.Cu")
		(net "M_A_CPU1_SB_DQ<0>")
	)
	(segment
		(start 65.896744 -231.684576)
		(end 64.157098 -231.684576)
		(width 0.18288)
		(layer "In2.Cu")
		(net "M_A_CPU1_SB_DQ<0>")
	)
	(segment
		(start 77.176884 -239.2807)
		(end 70.244462 -232.348278)
		(width 0.18288)
		(layer "In2.Cu")
		(net "M_A_CPU1_SB_DQ<0>")
	)
	(segment
		(start 89.281254 -238.720122)
		(end 89.272364 -238.715042)
		(width 0.088646)
		(layer "In2.Cu")
		(net "M_A_CPU1_SB_DQ<0>")
	)
	(segment
		(start 70.244462 -232.348278)
		(end 67.8942 -232.348278)
		(width 0.18288)
		(layer "In2.Cu")
		(net "M_A_CPU1_SB_DQ<0>")
	)
	(segment
		(start 88.427814 -239.528858)
		(end 88.413082 -239.537494)
		(width 0.088646)
		(layer "In2.Cu")
		(net "M_A_CPU1_SB_DQ<0>")
	)
	(segment
		(start 62.051946 -231.912414)
		(end 62.051946 -232.166668)
		(width 0.18288)
		(layer "In2.Cu")
		(net "M_A_CPU1_SB_DQ<0>")
	)
	(segment
		(start 63.964058 -231.167178)
		(end 63.66129 -230.86441)
		(width 0.18288)
		(layer "In2.Cu")
		(net "M_A_CPU1_SB_DQ<0>")
	)
	(segment
		(start 86.548214 -239.528858)
		(end 86.533482 -239.537494)
		(width 0.088646)
		(layer "In2.Cu")
		(net "M_A_CPU1_SB_DQ<0>")
	)
	(segment
		(start 89.085166 -239.0394)
		(end 89.398094 -239.0394)
		(width 0.088646)
		(layer "In2.Cu")
		(net "M_A_CPU1_SB_DQ<0>")
	)
	(segment
		(start 85.608414 -239.528858)
		(end 85.593682 -239.537494)
		(width 0.088646)
		(layer "In2.Cu")
		(net "M_A_CPU1_SB_DQ<0>")
	)
	(segment
		(start 88.897968 -238.715042)
		(end 88.889078 -238.720122)
		(width 0.088646)
		(layer "In2.Cu")
		(net "M_A_CPU1_SB_DQ<0>")
	)
	(segment
		(start 66.435224 -231.744012)
		(end 66.040254 -231.744012)
		(width 0.18288)
		(layer "In2.Cu")
		(net "M_A_CPU1_SB_DQ<0>")
	)
	(segment
		(start 62.158118 -231.806242)
		(end 62.051946 -231.912414)
		(width 0.18288)
		(layer "In2.Cu")
		(net "M_A_CPU1_SB_DQ<0>")
	)
	(segment
		(start 62.917578 -230.86441)
		(end 62.691518 -231.09047)
		(width 0.18288)
		(layer "In2.Cu")
		(net "M_A_CPU1_SB_DQ<0>")
	)
	(segment
		(start 64.157098 -231.684576)
		(end 63.964058 -231.491536)
		(width 0.18288)
		(layer "In2.Cu")
		(net "M_A_CPU1_SB_DQ<0>")
	)
	(segment
		(start 62.691518 -231.44353)
		(end 62.449202 -231.685846)
		(width 0.18288)
		(layer "In2.Cu")
		(net "M_A_CPU1_SB_DQ<0>")
	)
	(segment
		(start 63.964058 -231.491536)
		(end 63.964058 -231.167178)
		(width 0.18288)
		(layer "In2.Cu")
		(net "M_A_CPU1_SB_DQ<0>")
	)
	(segment
		(start 84.38642 -239.60455)
		(end 83.522566 -239.60455)
		(width 0.088646)
		(layer "In2.Cu")
		(net "M_A_CPU1_SB_DQ<0>")
	)
	(segment
		(start 66.040254 -231.744012)
		(end 65.896744 -231.684576)
		(width 0.18288)
		(layer "In2.Cu")
		(net "M_A_CPU1_SB_DQ<0>")
	)
	(segment
		(start 88.43391 -239.525302)
		(end 88.427814 -239.528858)
		(width 0.088646)
		(layer "In2.Cu")
		(net "M_A_CPU1_SB_DQ<0>")
	)
	(segment
		(start 82.759296 -239.2807)
		(end 77.176884 -239.2807)
		(width 0.18288)
		(layer "In2.Cu")
		(net "M_A_CPU1_SB_DQ<0>")
	)
	(segment
		(start 62.691518 -231.09047)
		(end 62.691518 -231.44353)
		(width 0.18288)
		(layer "In2.Cu")
		(net "M_A_CPU1_SB_DQ<0>")
	)
	(segment
		(start 62.449202 -231.685846)
		(end 62.158118 -231.806242)
		(width 0.18288)
		(layer "In2.Cu")
		(net "M_A_CPU1_SB_DQ<0>")
	)
	(segment
		(start 83.198716 -239.2807)
		(end 82.759296 -239.2807)
		(width 0.088646)
		(layer "In2.Cu")
		(net "M_A_CPU1_SB_DQ<0>")
	)
	(segment
		(start 67.8942 -232.348278)
		(end 66.435224 -231.744012)
		(width 0.18288)
		(layer "In2.Cu")
		(net "M_A_CPU1_SB_DQ<0>")
	)
	(segment
		(start 83.522566 -239.60455)
		(end 83.198716 -239.2807)
		(width 0.088646)
		(layer "In2.Cu")
		(net "M_A_CPU1_SB_DQ<0>")
	)
	(segment
		(start 87.488014 -239.528858)
		(end 87.473282 -239.537494)
		(width 0.088646)
		(layer "In2.Cu")
		(net "M_A_CPU1_SB_DQ<0>")
	)
	(segment
		(start 89.398094 -239.0394)
		(end 89.455244 -238.98225)
		(width 0.088646)
		(layer "In2.Cu")
		(net "M_A_CPU1_SB_DQ<0>")
	)
	(arc
		(start 85.593682 -239.537494)
		(mid 85.317207 -239.604814)
		(end 85.04301 -239.528858)
		(width 0.088646)
		(layer "In2.Cu")
		(net "M_A_CPU1_SB_DQ<0>")
	)
	(arc
		(start 86.92261 -239.528858)
		(mid 86.735412 -239.478715)
		(end 86.548214 -239.528858)
		(width 0.088646)
		(layer "In2.Cu")
		(net "M_A_CPU1_SB_DQ<0>")
	)
	(arc
		(start 85.04301 -239.528858)
		(mid 84.855812 -239.478715)
		(end 84.668614 -239.528858)
		(width 0.088646)
		(layer "In2.Cu")
		(net "M_A_CPU1_SB_DQ<0>")
	)
	(arc
		(start 87.473282 -239.537494)
		(mid 87.196807 -239.604814)
		(end 86.92261 -239.528858)
		(width 0.088646)
		(layer "In2.Cu")
		(net "M_A_CPU1_SB_DQ<0>")
	)
	(arc
		(start 88.710516 -239.0394)
		(mid 88.636525 -239.318966)
		(end 88.43391 -239.525302)
		(width 0.088646)
		(layer "In2.Cu")
		(net "M_A_CPU1_SB_DQ<0>")
	)
	(arc
		(start 88.413082 -239.537494)
		(mid 88.136607 -239.604814)
		(end 87.86241 -239.528858)
		(width 0.088646)
		(layer "In2.Cu")
		(net "M_A_CPU1_SB_DQ<0>")
	)
	(arc
		(start 86.533482 -239.537494)
		(mid 86.257007 -239.604814)
		(end 85.98281 -239.528858)
		(width 0.088646)
		(layer "In2.Cu")
		(net "M_A_CPU1_SB_DQ<0>")
	)
	(arc
		(start 89.455244 -238.98225)
		(mid 89.397125 -238.832009)
		(end 89.281254 -238.720122)
		(width 0.088646)
		(layer "In2.Cu")
		(net "M_A_CPU1_SB_DQ<0>")
	)
	(arc
		(start 89.272364 -238.715042)
		(mid 89.085166 -238.664899)
		(end 88.897968 -238.715042)
		(width 0.088646)
		(layer "In2.Cu")
		(net "M_A_CPU1_SB_DQ<0>")
	)
	(arc
		(start 88.889078 -238.720122)
		(mid 88.758164 -238.856482)
		(end 88.710516 -239.0394)
		(width 0.088646)
		(layer "In2.Cu")
		(net "M_A_CPU1_SB_DQ<0>")
	)
	(arc
		(start 85.98281 -239.528858)
		(mid 85.795612 -239.478715)
		(end 85.608414 -239.528858)
		(width 0.088646)
		(layer "In2.Cu")
		(net "M_A_CPU1_SB_DQ<0>")
	)
	(arc
		(start 84.668614 -239.528858)
		(mid 84.53249 -239.585234)
		(end 84.38642 -239.60455)
		(width 0.088646)
		(layer "In2.Cu")
		(net "M_A_CPU1_SB_DQ<0>")
	)
	(arc
		(start 87.86241 -239.528858)
		(mid 87.675212 -239.478715)
		(end 87.488014 -239.528858)
		(width 0.088646)
		(layer "In2.Cu")
		(net "M_A_CPU1_SB_DQ<0>")
	)
	(segment
		(start 80.876648 -246.272812)
		(end 74.82332 -246.272812)
		(width 0.1016)
		(layer "F.Cu")
		(net "M_A_CPU1_SB_CS_N<3>")
	)
	(segment
		(start 84.156296 -244.233192)
		(end 83.876896 -244.233192)
		(width 0.088646)
		(layer "F.Cu")
		(net "M_A_CPU1_SB_CS_N<3>")
	)
	(segment
		(start 65.650364 -244.916706)
		(end 65.047114 -244.916706)
		(width 0.20066)
		(layer "F.Cu")
		(net "M_A_CPU1_SB_CS_N<3>")
	)
	(segment
		(start 71.750428 -244.528086)
		(end 67.291966 -244.528086)
		(width 0.20066)
		(layer "F.Cu")
		(net "M_A_CPU1_SB_CS_N<3>")
	)
	(segment
		(start 86.735666 -243.644928)
		(end 86.284308 -244.096286)
		(width 0.088646)
		(layer "F.Cu")
		(net "M_A_CPU1_SB_CS_N<3>")
	)
	(segment
		(start 73.157588 -245.112032)
		(end 71.750428 -244.528086)
		(width 0.20066)
		(layer "F.Cu")
		(net "M_A_CPU1_SB_CS_N<3>")
	)
	(segment
		(start 84.19338 -244.196108)
		(end 84.156296 -244.233192)
		(width 0.088646)
		(layer "F.Cu")
		(net "M_A_CPU1_SB_CS_N<3>")
	)
	(segment
		(start 85.197188 -244.096286)
		(end 84.956142 -244.196108)
		(width 0.088646)
		(layer "F.Cu")
		(net "M_A_CPU1_SB_CS_N<3>")
	)
	(segment
		(start 74.82332 -246.272812)
		(end 74.02068 -245.470172)
		(width 0.1016)
		(layer "F.Cu")
		(net "M_A_CPU1_SB_CS_N<3>")
	)
	(segment
		(start 66.039238 -244.527832)
		(end 65.650364 -244.916706)
		(width 0.20066)
		(layer "F.Cu")
		(net "M_A_CPU1_SB_CS_N<3>")
	)
	(segment
		(start 67.291712 -244.527832)
		(end 66.039238 -244.527832)
		(width 0.20066)
		(layer "F.Cu")
		(net "M_A_CPU1_SB_CS_N<3>")
	)
	(segment
		(start 83.876896 -244.233192)
		(end 82.916268 -244.233192)
		(width 0.1016)
		(layer "F.Cu")
		(net "M_A_CPU1_SB_CS_N<3>")
	)
	(segment
		(start 84.956142 -244.196108)
		(end 84.19338 -244.196108)
		(width 0.088646)
		(layer "F.Cu")
		(net "M_A_CPU1_SB_CS_N<3>")
	)
	(segment
		(start 73.170288 -245.117366)
		(end 73.157588 -245.112032)
		(width 0.1016)
		(layer "F.Cu")
		(net "M_A_CPU1_SB_CS_N<3>")
	)
	(segment
		(start 82.916268 -244.233192)
		(end 80.876648 -246.272812)
		(width 0.1016)
		(layer "F.Cu")
		(net "M_A_CPU1_SB_CS_N<3>")
	)
	(segment
		(start 67.291966 -244.528086)
		(end 67.291712 -244.527832)
		(width 0.20066)
		(layer "F.Cu")
		(net "M_A_CPU1_SB_CS_N<3>")
	)
	(segment
		(start 74.02068 -245.470172)
		(end 73.170288 -245.117366)
		(width 0.1016)
		(layer "F.Cu")
		(net "M_A_CPU1_SB_CS_N<3>")
	)
	(segment
		(start 86.284308 -244.096286)
		(end 85.197188 -244.096286)
		(width 0.088646)
		(layer "F.Cu")
		(net "M_A_CPU1_SB_CS_N<3>")
	)
	(segment
		(start 81.129886 -246.882412)
		(end 74.41565 -246.882412)
		(width 0.1016)
		(layer "F.Cu")
		(net "M_A_CPU1_SB_CS_N<2>")
	)
	(segment
		(start 66.149982 -246.202454)
		(end 66.13906 -246.191532)
		(width 0.101854)
		(layer "F.Cu")
		(net "M_A_CPU1_SB_CS_N<2>")
	)
	(segment
		(start 66.186812 -246.202454)
		(end 66.149982 -246.202454)
		(width 0.101854)
		(layer "F.Cu")
		(net "M_A_CPU1_SB_CS_N<2>")
	)
	(segment
		(start 66.13906 -246.191532)
		(end 64.008508 -246.191532)
		(width 0.1016)
		(layer "F.Cu")
		(net "M_A_CPU1_SB_CS_N<2>")
	)
	(segment
		(start 86.85022 -244.55374)
		(end 86.452964 -244.783102)
		(width 0.088646)
		(layer "F.Cu")
		(net "M_A_CPU1_SB_CS_N<2>")
	)
	(segment
		(start 62.121542 -245.766336)
		(end 62.121288 -245.76659)
		(width 0.20066)
		(layer "F.Cu")
		(net "M_A_CPU1_SB_CS_N<2>")
	)
	(segment
		(start 66.55308 -246.202454)
		(end 66.186812 -246.202454)
		(width 0.20066)
		(layer "F.Cu")
		(net "M_A_CPU1_SB_CS_N<2>")
	)
	(segment
		(start 84.130896 -244.862604)
		(end 83.149694 -244.862604)
		(width 0.1016)
		(layer "F.Cu")
		(net "M_A_CPU1_SB_CS_N<2>")
	)
	(segment
		(start 63.977012 -246.214646)
		(end 62.569852 -246.214646)
		(width 0.20066)
		(layer "F.Cu")
		(net "M_A_CPU1_SB_CS_N<2>")
	)
	(segment
		(start 66.70294 -246.052594)
		(end 66.55308 -246.202454)
		(width 0.20066)
		(layer "F.Cu")
		(net "M_A_CPU1_SB_CS_N<2>")
	)
	(segment
		(start 73.013062 -246.502682)
		(end 73.001124 -246.497856)
		(width 0.1016)
		(layer "F.Cu")
		(net "M_A_CPU1_SB_CS_N<2>")
	)
	(segment
		(start 71.926958 -246.052594)
		(end 66.70294 -246.052594)
		(width 0.20066)
		(layer "F.Cu")
		(net "M_A_CPU1_SB_CS_N<2>")
	)
	(segment
		(start 73.001124 -246.497856)
		(end 71.926958 -246.052594)
		(width 0.20066)
		(layer "F.Cu")
		(net "M_A_CPU1_SB_CS_N<2>")
	)
	(segment
		(start 85.03539 -244.715538)
		(end 84.597494 -244.715538)
		(width 0.088646)
		(layer "F.Cu")
		(net "M_A_CPU1_SB_CS_N<2>")
	)
	(segment
		(start 84.242656 -244.862604)
		(end 84.130896 -244.862604)
		(width 0.088646)
		(layer "F.Cu")
		(net "M_A_CPU1_SB_CS_N<2>")
	)
	(segment
		(start 74.059034 -246.525796)
		(end 73.068942 -246.525796)
		(width 0.1016)
		(layer "F.Cu")
		(net "M_A_CPU1_SB_CS_N<2>")
	)
	(segment
		(start 85.064346 -244.744494)
		(end 85.03539 -244.715538)
		(width 0.088646)
		(layer "F.Cu")
		(net "M_A_CPU1_SB_CS_N<2>")
	)
	(segment
		(start 83.149694 -244.862604)
		(end 81.129886 -246.882412)
		(width 0.1016)
		(layer "F.Cu")
		(net "M_A_CPU1_SB_CS_N<2>")
	)
	(segment
		(start 86.078568 -244.783102)
		(end 86.068154 -244.777006)
		(width 0.088646)
		(layer "F.Cu")
		(net "M_A_CPU1_SB_CS_N<2>")
	)
	(segment
		(start 62.569852 -246.214646)
		(end 62.121542 -245.766336)
		(width 0.20066)
		(layer "F.Cu")
		(net "M_A_CPU1_SB_CS_N<2>")
	)
	(segment
		(start 74.41565 -246.882412)
		(end 74.059034 -246.525796)
		(width 0.1016)
		(layer "F.Cu")
		(net "M_A_CPU1_SB_CS_N<2>")
	)
	(segment
		(start 64.008508 -246.191532)
		(end 63.985394 -246.214646)
		(width 0.101854)
		(layer "F.Cu")
		(net "M_A_CPU1_SB_CS_N<2>")
	)
	(segment
		(start 84.597494 -244.715538)
		(end 84.242656 -244.862604)
		(width 0.088646)
		(layer "F.Cu")
		(net "M_A_CPU1_SB_CS_N<2>")
	)
	(segment
		(start 73.068942 -246.525796)
		(end 73.013062 -246.502682)
		(width 0.1016)
		(layer "F.Cu")
		(net "M_A_CPU1_SB_CS_N<2>")
	)
	(segment
		(start 62.121288 -245.76659)
		(end 60.947046 -245.76659)
		(width 0.20066)
		(layer "F.Cu")
		(net "M_A_CPU1_SB_CS_N<2>")
	)
	(segment
		(start 63.985394 -246.214646)
		(end 63.977012 -246.214646)
		(width 0.101854)
		(layer "F.Cu")
		(net "M_A_CPU1_SB_CS_N<2>")
	)
	(arc
		(start 86.452964 -244.783102)
		(mid 86.265766 -244.833245)
		(end 86.078568 -244.783102)
		(width 0.088646)
		(layer "F.Cu")
		(net "M_A_CPU1_SB_CS_N<2>")
	)
	(arc
		(start 85.51291 -244.783102)
		(mid 85.325712 -244.833245)
		(end 85.138514 -244.783102)
		(width 0.088646)
		(layer "F.Cu")
		(net "M_A_CPU1_SB_CS_N<2>")
	)
	(arc
		(start 87.205312 -244.458744)
		(mid 87.02151 -244.482864)
		(end 86.85022 -244.55374)
		(width 0.088646)
		(layer "F.Cu")
		(net "M_A_CPU1_SB_CS_N<2>")
	)
	(arc
		(start 86.068154 -244.777006)
		(mid 85.789722 -244.70716)
		(end 85.51291 -244.783102)
		(width 0.088646)
		(layer "F.Cu")
		(net "M_A_CPU1_SB_CS_N<2>")
	)
	(arc
		(start 85.138514 -244.783102)
		(mid 85.101862 -244.762968)
		(end 85.064346 -244.744494)
		(width 0.088646)
		(layer "F.Cu")
		(net "M_A_CPU1_SB_CS_N<2>")
	)
	(segment
		(start 85.795866 -243.644928)
		(end 85.538564 -243.90223)
		(width 0.088646)
		(layer "F.Cu")
		(net "M_A_CPU1_SB_CS_N<1>")
	)
	(segment
		(start 66.237612 -243.641626)
		(end 63.926212 -243.641626)
		(width 0.1016)
		(layer "F.Cu")
		(net "M_A_CPU1_SB_CS_N<1>")
	)
	(segment
		(start 73.338182 -244.488462)
		(end 71.293736 -243.641626)
		(width 0.20066)
		(layer "F.Cu")
		(net "M_A_CPU1_SB_CS_N<1>")
	)
	(segment
		(start 84.890864 -243.999258)
		(end 84.42198 -243.999258)
		(width 0.088646)
		(layer "F.Cu")
		(net "M_A_CPU1_SB_CS_N<1>")
	)
	(segment
		(start 82.815684 -243.90223)
		(end 80.749902 -245.968012)
		(width 0.1016)
		(layer "F.Cu")
		(net "M_A_CPU1_SB_CS_N<1>")
	)
	(segment
		(start 85.125052 -243.90223)
		(end 84.890864 -243.999258)
		(width 0.088646)
		(layer "F.Cu")
		(net "M_A_CPU1_SB_CS_N<1>")
	)
	(segment
		(start 59.940444 -244.49151)
		(end 59.925458 -244.476524)
		(width 0.101854)
		(layer "F.Cu")
		(net "M_A_CPU1_SB_CS_N<1>")
	)
	(segment
		(start 63.811912 -243.641626)
		(end 62.930786 -243.641626)
		(width 0.20066)
		(layer "F.Cu")
		(net "M_A_CPU1_SB_CS_N<1>")
	)
	(segment
		(start 62.132718 -244.49151)
		(end 62.072012 -244.49151)
		(width 0.101854)
		(layer "F.Cu")
		(net "M_A_CPU1_SB_CS_N<1>")
	)
	(segment
		(start 80.749902 -245.968012)
		(end 75.031092 -245.968012)
		(width 0.1016)
		(layer "F.Cu")
		(net "M_A_CPU1_SB_CS_N<1>")
	)
	(segment
		(start 84.187792 -243.90223)
		(end 83.876896 -243.90223)
		(width 0.088646)
		(layer "F.Cu")
		(net "M_A_CPU1_SB_CS_N<1>")
	)
	(segment
		(start 59.913012 -244.476524)
		(end 59.357514 -244.476524)
		(width 0.20066)
		(layer "F.Cu")
		(net "M_A_CPU1_SB_CS_N<1>")
	)
	(segment
		(start 83.876896 -243.90223)
		(end 82.815684 -243.90223)
		(width 0.1016)
		(layer "F.Cu")
		(net "M_A_CPU1_SB_CS_N<1>")
	)
	(segment
		(start 75.031092 -245.968012)
		(end 73.702418 -244.639338)
		(width 0.1016)
		(layer "F.Cu")
		(net "M_A_CPU1_SB_CS_N<1>")
	)
	(segment
		(start 84.42198 -243.999258)
		(end 84.187792 -243.90223)
		(width 0.088646)
		(layer "F.Cu")
		(net "M_A_CPU1_SB_CS_N<1>")
	)
	(segment
		(start 59.357514 -244.476524)
		(end 58.917332 -244.916706)
		(width 0.20066)
		(layer "F.Cu")
		(net "M_A_CPU1_SB_CS_N<1>")
	)
	(segment
		(start 71.293736 -243.641626)
		(end 66.237612 -243.641626)
		(width 0.20066)
		(layer "F.Cu")
		(net "M_A_CPU1_SB_CS_N<1>")
	)
	(segment
		(start 62.072012 -244.49151)
		(end 59.940444 -244.49151)
		(width 0.1016)
		(layer "F.Cu")
		(net "M_A_CPU1_SB_CS_N<1>")
	)
	(segment
		(start 59.925458 -244.476524)
		(end 59.913012 -244.476524)
		(width 0.101854)
		(layer "F.Cu")
		(net "M_A_CPU1_SB_CS_N<1>")
	)
	(segment
		(start 73.702418 -244.639338)
		(end 73.338182 -244.488462)
		(width 0.1016)
		(layer "F.Cu")
		(net "M_A_CPU1_SB_CS_N<1>")
	)
	(segment
		(start 62.75578 -243.816632)
		(end 62.75578 -244.086634)
		(width 0.20066)
		(layer "F.Cu")
		(net "M_A_CPU1_SB_CS_N<1>")
	)
	(segment
		(start 58.917332 -244.916706)
		(end 57.503314 -244.916706)
		(width 0.20066)
		(layer "F.Cu")
		(net "M_A_CPU1_SB_CS_N<1>")
	)
	(segment
		(start 85.538564 -243.90223)
		(end 85.125052 -243.90223)
		(width 0.088646)
		(layer "F.Cu")
		(net "M_A_CPU1_SB_CS_N<1>")
	)
	(segment
		(start 63.926212 -243.641626)
		(end 63.811912 -243.641626)
		(width 0.101854)
		(layer "F.Cu")
		(net "M_A_CPU1_SB_CS_N<1>")
	)
	(segment
		(start 62.75578 -244.086634)
		(end 62.350904 -244.49151)
		(width 0.20066)
		(layer "F.Cu")
		(net "M_A_CPU1_SB_CS_N<1>")
	)
	(segment
		(start 62.930786 -243.641626)
		(end 62.75578 -243.816632)
		(width 0.20066)
		(layer "F.Cu")
		(net "M_A_CPU1_SB_CS_N<1>")
	)
	(segment
		(start 62.350904 -244.49151)
		(end 62.132718 -244.49151)
		(width 0.20066)
		(layer "F.Cu")
		(net "M_A_CPU1_SB_CS_N<1>")
	)
	(segment
		(start 61.99378 -245.341648)
		(end 62.00775 -245.355618)
		(width 0.101854)
		(layer "F.Cu")
		(net "M_A_CPU1_SB_CS_N<0>")
	)
	(segment
		(start 73.979532 -245.890796)
		(end 74.666348 -246.577612)
		(width 0.1016)
		(layer "F.Cu")
		(net "M_A_CPU1_SB_CS_N<0>")
	)
	(segment
		(start 58.770266 -245.332504)
		(end 58.796174 -245.358412)
		(width 0.20066)
		(layer "F.Cu")
		(net "M_A_CPU1_SB_CS_N<0>")
	)
	(segment
		(start 56.517032 -245.341648)
		(end 58.564272 -245.341648)
		(width 0.1016)
		(layer "F.Cu")
		(net "M_A_CPU1_SB_CS_N<0>")
	)
	(segment
		(start 73.27011 -245.890796)
		(end 73.979532 -245.890796)
		(width 0.1016)
		(layer "F.Cu")
		(net "M_A_CPU1_SB_CS_N<0>")
	)
	(segment
		(start 58.796174 -245.358412)
		(end 59.913012 -245.358412)
		(width 0.20066)
		(layer "F.Cu")
		(net "M_A_CPU1_SB_CS_N<0>")
	)
	(segment
		(start 55.067962 -245.391432)
		(end 55.067962 -244.883432)
		(width 0.20066)
		(layer "F.Cu")
		(net "M_A_CPU1_SB_CS_N<0>")
	)
	(segment
		(start 58.617612 -245.332504)
		(end 58.770266 -245.332504)
		(width 0.20066)
		(layer "F.Cu")
		(net "M_A_CPU1_SB_CS_N<0>")
	)
	(segment
		(start 73.133204 -245.834154)
		(end 73.145142 -245.83898)
		(width 0.101854)
		(layer "F.Cu")
		(net "M_A_CPU1_SB_CS_N<0>")
	)
	(segment
		(start 62.00775 -245.355618)
		(end 62.072012 -245.355618)
		(width 0.101854)
		(layer "F.Cu")
		(net "M_A_CPU1_SB_CS_N<0>")
	)
	(segment
		(start 71.91756 -245.330472)
		(end 73.133204 -245.834154)
		(width 0.20066)
		(layer "F.Cu")
		(net "M_A_CPU1_SB_CS_N<0>")
	)
	(segment
		(start 64.002412 -245.326662)
		(end 64.026034 -245.326662)
		(width 0.101854)
		(layer "F.Cu")
		(net "M_A_CPU1_SB_CS_N<0>")
	)
	(segment
		(start 58.573416 -245.332504)
		(end 58.617612 -245.332504)
		(width 0.101854)
		(layer "F.Cu")
		(net "M_A_CPU1_SB_CS_N<0>")
	)
	(segment
		(start 53.403246 -245.76659)
		(end 54.692804 -245.76659)
		(width 0.20066)
		(layer "F.Cu")
		(net "M_A_CPU1_SB_CS_N<0>")
	)
	(segment
		(start 73.145142 -245.83898)
		(end 73.156826 -245.843806)
		(width 0.1016)
		(layer "F.Cu")
		(net "M_A_CPU1_SB_CS_N<0>")
	)
	(segment
		(start 56.170576 -245.333774)
		(end 56.484012 -245.333774)
		(width 0.20066)
		(layer "F.Cu")
		(net "M_A_CPU1_SB_CS_N<0>")
	)
	(segment
		(start 84.208874 -244.539516)
		(end 84.289646 -244.458744)
		(width 0.088646)
		(layer "F.Cu")
		(net "M_A_CPU1_SB_CS_N<0>")
	)
	(segment
		(start 55.067962 -244.883432)
		(end 55.243222 -244.708172)
		(width 0.20066)
		(layer "F.Cu")
		(net "M_A_CPU1_SB_CS_N<0>")
	)
	(segment
		(start 64.04102 -245.341648)
		(end 66.151252 -245.341648)
		(width 0.1016)
		(layer "F.Cu")
		(net "M_A_CPU1_SB_CS_N<0>")
	)
	(segment
		(start 56.484012 -245.333774)
		(end 56.509158 -245.333774)
		(width 0.101854)
		(layer "F.Cu")
		(net "M_A_CPU1_SB_CS_N<0>")
	)
	(segment
		(start 66.186812 -245.330472)
		(end 71.91756 -245.330472)
		(width 0.20066)
		(layer "F.Cu")
		(net "M_A_CPU1_SB_CS_N<0>")
	)
	(segment
		(start 55.631842 -244.708172)
		(end 55.807102 -244.883432)
		(width 0.20066)
		(layer "F.Cu")
		(net "M_A_CPU1_SB_CS_N<0>")
	)
	(segment
		(start 55.243222 -244.708172)
		(end 55.631842 -244.708172)
		(width 0.20066)
		(layer "F.Cu")
		(net "M_A_CPU1_SB_CS_N<0>")
	)
	(segment
		(start 83.041236 -244.539516)
		(end 83.876896 -244.539516)
		(width 0.1016)
		(layer "F.Cu")
		(net "M_A_CPU1_SB_CS_N<0>")
	)
	(segment
		(start 83.876896 -244.539516)
		(end 84.208874 -244.539516)
		(width 0.088646)
		(layer "F.Cu")
		(net "M_A_CPU1_SB_CS_N<0>")
	)
	(segment
		(start 58.564272 -245.341648)
		(end 58.573416 -245.332504)
		(width 0.101854)
		(layer "F.Cu")
		(net "M_A_CPU1_SB_CS_N<0>")
	)
	(segment
		(start 63.721234 -245.326662)
		(end 64.002412 -245.326662)
		(width 0.20066)
		(layer "F.Cu")
		(net "M_A_CPU1_SB_CS_N<0>")
	)
	(segment
		(start 66.151252 -245.341648)
		(end 66.162428 -245.330472)
		(width 0.101854)
		(layer "F.Cu")
		(net "M_A_CPU1_SB_CS_N<0>")
	)
	(segment
		(start 55.807102 -244.9703)
		(end 56.170576 -245.333774)
		(width 0.20066)
		(layer "F.Cu")
		(net "M_A_CPU1_SB_CS_N<0>")
	)
	(segment
		(start 74.666348 -246.577612)
		(end 81.00314 -246.577612)
		(width 0.1016)
		(layer "F.Cu")
		(net "M_A_CPU1_SB_CS_N<0>")
	)
	(segment
		(start 64.026034 -245.326662)
		(end 64.04102 -245.341648)
		(width 0.101854)
		(layer "F.Cu")
		(net "M_A_CPU1_SB_CS_N<0>")
	)
	(segment
		(start 66.162428 -245.330472)
		(end 66.186812 -245.330472)
		(width 0.101854)
		(layer "F.Cu")
		(net "M_A_CPU1_SB_CS_N<0>")
	)
	(segment
		(start 81.00314 -246.577612)
		(end 83.041236 -244.539516)
		(width 0.1016)
		(layer "F.Cu")
		(net "M_A_CPU1_SB_CS_N<0>")
	)
	(segment
		(start 59.95416 -245.358412)
		(end 59.970924 -245.341648)
		(width 0.101854)
		(layer "F.Cu")
		(net "M_A_CPU1_SB_CS_N<0>")
	)
	(segment
		(start 55.807102 -244.883432)
		(end 55.807102 -244.9703)
		(width 0.20066)
		(layer "F.Cu")
		(net "M_A_CPU1_SB_CS_N<0>")
	)
	(segment
		(start 59.970924 -245.341648)
		(end 61.99378 -245.341648)
		(width 0.1016)
		(layer "F.Cu")
		(net "M_A_CPU1_SB_CS_N<0>")
	)
	(segment
		(start 84.289646 -244.458744)
		(end 85.325712 -244.458744)
		(width 0.088646)
		(layer "F.Cu")
		(net "M_A_CPU1_SB_CS_N<0>")
	)
	(segment
		(start 73.156826 -245.843806)
		(end 73.27011 -245.890796)
		(width 0.1016)
		(layer "F.Cu")
		(net "M_A_CPU1_SB_CS_N<0>")
	)
	(segment
		(start 54.692804 -245.76659)
		(end 55.067962 -245.391432)
		(width 0.20066)
		(layer "F.Cu")
		(net "M_A_CPU1_SB_CS_N<0>")
	)
	(segment
		(start 63.692278 -245.355618)
		(end 63.721234 -245.326662)
		(width 0.20066)
		(layer "F.Cu")
		(net "M_A_CPU1_SB_CS_N<0>")
	)
	(segment
		(start 59.913012 -245.358412)
		(end 59.95416 -245.358412)
		(width 0.101854)
		(layer "F.Cu")
		(net "M_A_CPU1_SB_CS_N<0>")
	)
	(segment
		(start 62.072012 -245.355618)
		(end 63.692278 -245.355618)
		(width 0.20066)
		(layer "F.Cu")
		(net "M_A_CPU1_SB_CS_N<0>")
	)
	(segment
		(start 56.509158 -245.333774)
		(end 56.517032 -245.341648)
		(width 0.101854)
		(layer "F.Cu")
		(net "M_A_CPU1_SB_CS_N<0>")
	)
	(segment
		(start 78.057502 -241.079782)
		(end 77.747622 -241.079782)
		(width 0.20066)
		(layer "F.Cu")
		(net "M_A_CPU1_SB_CB<7>")
	)
	(segment
		(start 80.391762 -241.280442)
		(end 80.391762 -241.389154)
		(width 0.20066)
		(layer "F.Cu")
		(net "M_A_CPU1_SB_CB<7>")
	)
	(segment
		(start 62.42685 -239.391698)
		(end 62.552072 -239.391698)
		(width 0.20066)
		(layer "F.Cu")
		(net "M_A_CPU1_SB_CB<7>")
	)
	(segment
		(start 75.348592 -241.554508)
		(end 74.872088 -241.078004)
		(width 0.20066)
		(layer "F.Cu")
		(net "M_A_CPU1_SB_CB<7>")
	)
	(segment
		(start 80.592422 -241.079782)
		(end 80.391762 -241.280442)
		(width 0.20066)
		(layer "F.Cu")
		(net "M_A_CPU1_SB_CB<7>")
	)
	(segment
		(start 87.081868 -240.841276)
		(end 87.018622 -240.878106)
		(width 0.088646)
		(layer "F.Cu")
		(net "M_A_CPU1_SB_CB<7>")
	)
	(segment
		(start 66.95567 -238.966756)
		(end 65.047114 -238.966756)
		(width 0.20066)
		(layer "F.Cu")
		(net "M_A_CPU1_SB_CB<7>")
	)
	(segment
		(start 82.409284 -241.554508)
		(end 81.717896 -241.554508)
		(width 0.1016)
		(layer "F.Cu")
		(net "M_A_CPU1_SB_CB<7>")
	)
	(segment
		(start 79.170022 -241.079782)
		(end 78.969362 -241.280442)
		(width 0.20066)
		(layer "F.Cu")
		(net "M_A_CPU1_SB_CB<7>")
	)
	(segment
		(start 62.072012 -239.391698)
		(end 62.42685 -239.391698)
		(width 0.101854)
		(layer "F.Cu")
		(net "M_A_CPU1_SB_CB<7>")
	)
	(segment
		(start 84.844636 -240.958116)
		(end 84.337144 -240.958116)
		(width 0.088646)
		(layer "F.Cu")
		(net "M_A_CPU1_SB_CB<7>")
	)
	(segment
		(start 76.835762 -241.389154)
		(end 76.835762 -241.280442)
		(width 0.20066)
		(layer "F.Cu")
		(net "M_A_CPU1_SB_CB<7>")
	)
	(segment
		(start 67.664584 -239.67567)
		(end 66.95567 -238.966756)
		(width 0.20066)
		(layer "F.Cu")
		(net "M_A_CPU1_SB_CB<7>")
	)
	(segment
		(start 78.969362 -241.280442)
		(end 78.969362 -241.353848)
		(width 0.20066)
		(layer "F.Cu")
		(net "M_A_CPU1_SB_CB<7>")
	)
	(segment
		(start 75.850496 -241.554508)
		(end 75.348592 -241.554508)
		(width 0.20066)
		(layer "F.Cu")
		(net "M_A_CPU1_SB_CB<7>")
	)
	(segment
		(start 59.458098 -239.391698)
		(end 59.515248 -239.391698)
		(width 0.20066)
		(layer "F.Cu")
		(net "M_A_CPU1_SB_CB<7>")
	)
	(segment
		(start 77.036422 -241.589814)
		(end 76.835762 -241.389154)
		(width 0.20066)
		(layer "F.Cu")
		(net "M_A_CPU1_SB_CB<7>")
	)
	(segment
		(start 83.076796 -240.886996)
		(end 82.982562 -240.98123)
		(width 0.088646)
		(layer "F.Cu")
		(net "M_A_CPU1_SB_CB<7>")
	)
	(segment
		(start 78.258162 -241.353848)
		(end 78.258162 -241.280442)
		(width 0.20066)
		(layer "F.Cu")
		(net "M_A_CPU1_SB_CB<7>")
	)
	(segment
		(start 82.982562 -240.98123)
		(end 82.409284 -241.554508)
		(width 0.1016)
		(layer "F.Cu")
		(net "M_A_CPU1_SB_CB<7>")
	)
	(segment
		(start 59.862212 -239.391698)
		(end 62.072012 -239.391698)
		(width 0.1016)
		(layer "F.Cu")
		(net "M_A_CPU1_SB_CB<7>")
	)
	(segment
		(start 77.546962 -241.389154)
		(end 77.346302 -241.589814)
		(width 0.20066)
		(layer "F.Cu")
		(net "M_A_CPU1_SB_CB<7>")
	)
	(segment
		(start 87.009224 -240.88344)
		(end 86.90356 -240.942114)
		(width 0.088646)
		(layer "F.Cu")
		(net "M_A_CPU1_SB_CB<7>")
	)
	(segment
		(start 71.486014 -239.67567)
		(end 67.664584 -239.67567)
		(width 0.20066)
		(layer "F.Cu")
		(net "M_A_CPU1_SB_CB<7>")
	)
	(segment
		(start 78.969362 -241.353848)
		(end 78.768702 -241.554508)
		(width 0.20066)
		(layer "F.Cu")
		(net "M_A_CPU1_SB_CB<7>")
	)
	(segment
		(start 80.902302 -241.079782)
		(end 80.592422 -241.079782)
		(width 0.20066)
		(layer "F.Cu")
		(net "M_A_CPU1_SB_CB<7>")
	)
	(segment
		(start 81.102962 -241.353848)
		(end 81.102962 -241.280442)
		(width 0.20066)
		(layer "F.Cu")
		(net "M_A_CPU1_SB_CB<7>")
	)
	(segment
		(start 76.325222 -241.079782)
		(end 75.850496 -241.554508)
		(width 0.20066)
		(layer "F.Cu")
		(net "M_A_CPU1_SB_CB<7>")
	)
	(segment
		(start 62.552072 -239.391698)
		(end 62.732412 -239.211358)
		(width 0.20066)
		(layer "F.Cu")
		(net "M_A_CPU1_SB_CB<7>")
	)
	(segment
		(start 78.768702 -241.554508)
		(end 78.458822 -241.554508)
		(width 0.20066)
		(layer "F.Cu")
		(net "M_A_CPU1_SB_CB<7>")
	)
	(segment
		(start 59.515248 -239.391698)
		(end 59.862212 -239.391698)
		(width 0.101854)
		(layer "F.Cu")
		(net "M_A_CPU1_SB_CB<7>")
	)
	(segment
		(start 77.747622 -241.079782)
		(end 77.546962 -241.280442)
		(width 0.20066)
		(layer "F.Cu")
		(net "M_A_CPU1_SB_CB<7>")
	)
	(segment
		(start 62.836298 -238.75365)
		(end 63.120524 -238.75365)
		(width 0.20066)
		(layer "F.Cu")
		(net "M_A_CPU1_SB_CB<7>")
	)
	(segment
		(start 57.503314 -238.966756)
		(end 59.033156 -238.966756)
		(width 0.20066)
		(layer "F.Cu")
		(net "M_A_CPU1_SB_CB<7>")
	)
	(segment
		(start 85.263736 -240.816892)
		(end 85.127084 -240.88217)
		(width 0.088646)
		(layer "F.Cu")
		(net "M_A_CPU1_SB_CB<7>")
	)
	(segment
		(start 80.191102 -241.589814)
		(end 79.881222 -241.589814)
		(width 0.20066)
		(layer "F.Cu")
		(net "M_A_CPU1_SB_CB<7>")
	)
	(segment
		(start 78.458822 -241.554508)
		(end 78.258162 -241.353848)
		(width 0.20066)
		(layer "F.Cu")
		(net "M_A_CPU1_SB_CB<7>")
	)
	(segment
		(start 86.452964 -240.878868)
		(end 86.385908 -240.84026)
		(width 0.088646)
		(layer "F.Cu")
		(net "M_A_CPU1_SB_CB<7>")
	)
	(segment
		(start 87.547958 -240.894362)
		(end 87.470742 -240.817146)
		(width 0.088646)
		(layer "F.Cu")
		(net "M_A_CPU1_SB_CB<7>")
	)
	(segment
		(start 87.415116 -241.203226)
		(end 87.547958 -241.070384)
		(width 0.088646)
		(layer "F.Cu")
		(net "M_A_CPU1_SB_CB<7>")
	)
	(segment
		(start 79.680562 -241.280442)
		(end 79.479902 -241.079782)
		(width 0.20066)
		(layer "F.Cu")
		(net "M_A_CPU1_SB_CB<7>")
	)
	(segment
		(start 79.680562 -241.389154)
		(end 79.680562 -241.280442)
		(width 0.20066)
		(layer "F.Cu")
		(net "M_A_CPU1_SB_CB<7>")
	)
	(segment
		(start 87.470742 -240.817146)
		(end 87.171276 -240.817146)
		(width 0.088646)
		(layer "F.Cu")
		(net "M_A_CPU1_SB_CB<7>")
	)
	(segment
		(start 87.205312 -241.203226)
		(end 87.415116 -241.203226)
		(width 0.088646)
		(layer "F.Cu")
		(net "M_A_CPU1_SB_CB<7>")
	)
	(segment
		(start 62.732412 -239.211358)
		(end 62.732412 -238.857536)
		(width 0.20066)
		(layer "F.Cu")
		(net "M_A_CPU1_SB_CB<7>")
	)
	(segment
		(start 63.33363 -238.966756)
		(end 65.047114 -238.966756)
		(width 0.20066)
		(layer "F.Cu")
		(net "M_A_CPU1_SB_CB<7>")
	)
	(segment
		(start 63.120524 -238.75365)
		(end 63.33363 -238.966756)
		(width 0.20066)
		(layer "F.Cu")
		(net "M_A_CPU1_SB_CB<7>")
	)
	(segment
		(start 84.337144 -240.958116)
		(end 84.266024 -240.886996)
		(width 0.088646)
		(layer "F.Cu")
		(net "M_A_CPU1_SB_CB<7>")
	)
	(segment
		(start 62.732412 -238.857536)
		(end 62.836298 -238.75365)
		(width 0.20066)
		(layer "F.Cu")
		(net "M_A_CPU1_SB_CB<7>")
	)
	(segment
		(start 79.479902 -241.079782)
		(end 79.170022 -241.079782)
		(width 0.20066)
		(layer "F.Cu")
		(net "M_A_CPU1_SB_CB<7>")
	)
	(segment
		(start 77.346302 -241.589814)
		(end 77.036422 -241.589814)
		(width 0.20066)
		(layer "F.Cu")
		(net "M_A_CPU1_SB_CB<7>")
	)
	(segment
		(start 76.835762 -241.280442)
		(end 76.635102 -241.079782)
		(width 0.20066)
		(layer "F.Cu")
		(net "M_A_CPU1_SB_CB<7>")
	)
	(segment
		(start 79.881222 -241.589814)
		(end 79.680562 -241.389154)
		(width 0.20066)
		(layer "F.Cu")
		(net "M_A_CPU1_SB_CB<7>")
	)
	(segment
		(start 76.635102 -241.079782)
		(end 76.325222 -241.079782)
		(width 0.20066)
		(layer "F.Cu")
		(net "M_A_CPU1_SB_CB<7>")
	)
	(segment
		(start 86.233 -240.799366)
		(end 85.340952 -240.799366)
		(width 0.088646)
		(layer "F.Cu")
		(net "M_A_CPU1_SB_CB<7>")
	)
	(segment
		(start 80.391762 -241.389154)
		(end 80.191102 -241.589814)
		(width 0.20066)
		(layer "F.Cu")
		(net "M_A_CPU1_SB_CB<7>")
	)
	(segment
		(start 81.303622 -241.554508)
		(end 81.102962 -241.353848)
		(width 0.20066)
		(layer "F.Cu")
		(net "M_A_CPU1_SB_CB<7>")
	)
	(segment
		(start 59.033156 -238.966756)
		(end 59.458098 -239.391698)
		(width 0.20066)
		(layer "F.Cu")
		(net "M_A_CPU1_SB_CB<7>")
	)
	(segment
		(start 84.266024 -240.886996)
		(end 83.076796 -240.886996)
		(width 0.088646)
		(layer "F.Cu")
		(net "M_A_CPU1_SB_CB<7>")
	)
	(segment
		(start 81.717896 -241.554508)
		(end 81.303622 -241.554508)
		(width 0.20066)
		(layer "F.Cu")
		(net "M_A_CPU1_SB_CB<7>")
	)
	(segment
		(start 81.102962 -241.280442)
		(end 80.902302 -241.079782)
		(width 0.20066)
		(layer "F.Cu")
		(net "M_A_CPU1_SB_CB<7>")
	)
	(segment
		(start 87.547958 -241.070384)
		(end 87.547958 -240.894362)
		(width 0.088646)
		(layer "F.Cu")
		(net "M_A_CPU1_SB_CB<7>")
	)
	(segment
		(start 78.258162 -241.280442)
		(end 78.057502 -241.079782)
		(width 0.20066)
		(layer "F.Cu")
		(net "M_A_CPU1_SB_CB<7>")
	)
	(segment
		(start 74.872088 -241.078004)
		(end 71.486014 -239.67567)
		(width 0.20066)
		(layer "F.Cu")
		(net "M_A_CPU1_SB_CB<7>")
	)
	(segment
		(start 77.546962 -241.280442)
		(end 77.546962 -241.389154)
		(width 0.20066)
		(layer "F.Cu")
		(net "M_A_CPU1_SB_CB<7>")
	)
	(arc
		(start 85.340952 -240.799366)
		(mid 85.301357 -240.803792)
		(end 85.263736 -240.816892)
		(width 0.088646)
		(layer "F.Cu")
		(net "M_A_CPU1_SB_CB<7>")
	)
	(arc
		(start 86.90356 -240.942114)
		(mid 86.667667 -240.985925)
		(end 86.452964 -240.878868)
		(width 0.088646)
		(layer "F.Cu")
		(net "M_A_CPU1_SB_CB<7>")
	)
	(arc
		(start 85.127084 -240.88217)
		(mid 84.990858 -240.938727)
		(end 84.844636 -240.958116)
		(width 0.088646)
		(layer "F.Cu")
		(net "M_A_CPU1_SB_CB<7>")
	)
	(arc
		(start 86.385908 -240.84026)
		(mid 86.312137 -240.809792)
		(end 86.233 -240.799366)
		(width 0.088646)
		(layer "F.Cu")
		(net "M_A_CPU1_SB_CB<7>")
	)
	(arc
		(start 87.018622 -240.878106)
		(mid 87.013935 -240.880795)
		(end 87.009224 -240.88344)
		(width 0.088646)
		(layer "F.Cu")
		(net "M_A_CPU1_SB_CB<7>")
	)
	(arc
		(start 87.171276 -240.817146)
		(mid 87.124975 -240.823289)
		(end 87.081868 -240.841276)
		(width 0.088646)
		(layer "F.Cu")
		(net "M_A_CPU1_SB_CB<7>")
	)
	(segment
		(start 83.339686 -241.486944)
		(end 81.957672 -242.868958)
		(width 0.1016)
		(layer "F.Cu")
		(net "M_A_CPU1_SB_CB<6>")
	)
	(segment
		(start 76.129642 -242.884706)
		(end 75.819762 -242.884706)
		(width 0.20066)
		(layer "F.Cu")
		(net "M_A_CPU1_SB_CB<6>")
	)
	(segment
		(start 73.613772 -242.138962)
		(end 71.154544 -241.120422)
		(width 0.20066)
		(layer "F.Cu")
		(net "M_A_CPU1_SB_CB<6>")
	)
	(segment
		(start 86.735666 -242.017042)
		(end 86.078314 -241.744754)
		(width 0.088646)
		(layer "F.Cu")
		(net "M_A_CPU1_SB_CB<6>")
	)
	(segment
		(start 81.692496 -243.135658)
		(end 81.412588 -243.415566)
		(width 0.20066)
		(layer "F.Cu")
		(net "M_A_CPU1_SB_CB<6>")
	)
	(segment
		(start 85.958426 -241.624866)
		(end 85.958426 -241.43208)
		(width 0.088646)
		(layer "F.Cu")
		(net "M_A_CPU1_SB_CB<6>")
	)
	(segment
		(start 85.869526 -241.34318)
		(end 85.718904 -241.34318)
		(width 0.088646)
		(layer "F.Cu")
		(net "M_A_CPU1_SB_CB<6>")
	)
	(segment
		(start 76.530962 -243.415566)
		(end 76.330302 -243.214906)
		(width 0.20066)
		(layer "F.Cu")
		(net "M_A_CPU1_SB_CB<6>")
	)
	(segment
		(start 81.957672 -242.868958)
		(end 81.957672 -242.870482)
		(width 0.1016)
		(layer "F.Cu")
		(net "M_A_CPU1_SB_CB<6>")
	)
	(segment
		(start 83.387692 -241.438938)
		(end 83.339686 -241.486944)
		(width 0.088646)
		(layer "F.Cu")
		(net "M_A_CPU1_SB_CB<6>")
	)
	(segment
		(start 75.418442 -243.415566)
		(end 74.890376 -243.415566)
		(width 0.20066)
		(layer "F.Cu")
		(net "M_A_CPU1_SB_CB<6>")
	)
	(segment
		(start 84.892642 -241.452908)
		(end 84.878672 -241.438938)
		(width 0.088646)
		(layer "F.Cu")
		(net "M_A_CPU1_SB_CB<6>")
	)
	(segment
		(start 62.21349 -241.09172)
		(end 62.580012 -241.09172)
		(width 0.20066)
		(layer "F.Cu")
		(net "M_A_CPU1_SB_CB<6>")
	)
	(segment
		(start 85.718904 -241.34318)
		(end 85.628226 -241.433858)
		(width 0.088646)
		(layer "F.Cu")
		(net "M_A_CPU1_SB_CB<6>")
	)
	(segment
		(start 66.39306 -240.507266)
		(end 66.233548 -240.666778)
		(width 0.20066)
		(layer "F.Cu")
		(net "M_A_CPU1_SB_CB<6>")
	)
	(segment
		(start 63.439294 -240.666778)
		(end 65.047114 -240.666778)
		(width 0.20066)
		(layer "F.Cu")
		(net "M_A_CPU1_SB_CB<6>")
	)
	(segment
		(start 78.664562 -242.884706)
		(end 78.463902 -243.085366)
		(width 0.20066)
		(layer "F.Cu")
		(net "M_A_CPU1_SB_CB<6>")
	)
	(segment
		(start 57.503314 -240.666778)
		(end 59.23026 -240.666778)
		(width 0.20066)
		(layer "F.Cu")
		(net "M_A_CPU1_SB_CB<6>")
	)
	(segment
		(start 66.233548 -240.666778)
		(end 65.047114 -240.666778)
		(width 0.20066)
		(layer "F.Cu")
		(net "M_A_CPU1_SB_CB<6>")
	)
	(segment
		(start 80.597502 -243.085366)
		(end 80.396842 -242.884706)
		(width 0.20066)
		(layer "F.Cu")
		(net "M_A_CPU1_SB_CB<6>")
	)
	(segment
		(start 77.041502 -243.214906)
		(end 76.840842 -243.415566)
		(width 0.20066)
		(layer "F.Cu")
		(net "M_A_CPU1_SB_CB<6>")
	)
	(segment
		(start 76.840842 -243.415566)
		(end 76.530962 -243.415566)
		(width 0.20066)
		(layer "F.Cu")
		(net "M_A_CPU1_SB_CB<6>")
	)
	(segment
		(start 76.330302 -243.085366)
		(end 76.129642 -242.884706)
		(width 0.20066)
		(layer "F.Cu")
		(net "M_A_CPU1_SB_CB<6>")
	)
	(segment
		(start 86.078314 -241.744754)
		(end 85.958426 -241.624866)
		(width 0.088646)
		(layer "F.Cu")
		(net "M_A_CPU1_SB_CB<6>")
	)
	(segment
		(start 77.953362 -243.415566)
		(end 77.752702 -243.214906)
		(width 0.20066)
		(layer "F.Cu")
		(net "M_A_CPU1_SB_CB<6>")
	)
	(segment
		(start 78.463902 -243.085366)
		(end 78.463902 -243.214906)
		(width 0.20066)
		(layer "F.Cu")
		(net "M_A_CPU1_SB_CB<6>")
	)
	(segment
		(start 62.580012 -241.09172)
		(end 62.669928 -241.001804)
		(width 0.20066)
		(layer "F.Cu")
		(net "M_A_CPU1_SB_CB<6>")
	)
	(segment
		(start 59.655964 -241.092482)
		(end 59.692794 -241.092482)
		(width 0.20066)
		(layer "F.Cu")
		(net "M_A_CPU1_SB_CB<6>")
	)
	(segment
		(start 78.263242 -243.415566)
		(end 77.953362 -243.415566)
		(width 0.20066)
		(layer "F.Cu")
		(net "M_A_CPU1_SB_CB<6>")
	)
	(segment
		(start 77.041502 -243.085366)
		(end 77.041502 -243.214906)
		(width 0.20066)
		(layer "F.Cu")
		(net "M_A_CPU1_SB_CB<6>")
	)
	(segment
		(start 59.805062 -241.09172)
		(end 62.072012 -241.09172)
		(width 0.1016)
		(layer "F.Cu")
		(net "M_A_CPU1_SB_CB<6>")
	)
	(segment
		(start 78.463902 -243.214906)
		(end 78.263242 -243.415566)
		(width 0.20066)
		(layer "F.Cu")
		(net "M_A_CPU1_SB_CB<6>")
	)
	(segment
		(start 62.669928 -240.610898)
		(end 62.796928 -240.483898)
		(width 0.20066)
		(layer "F.Cu")
		(net "M_A_CPU1_SB_CB<6>")
	)
	(segment
		(start 79.375762 -243.415566)
		(end 79.175102 -243.214906)
		(width 0.20066)
		(layer "F.Cu")
		(net "M_A_CPU1_SB_CB<6>")
	)
	(segment
		(start 75.819762 -242.884706)
		(end 75.619102 -243.085366)
		(width 0.20066)
		(layer "F.Cu")
		(net "M_A_CPU1_SB_CB<6>")
	)
	(segment
		(start 62.669928 -241.001804)
		(end 62.669928 -240.610898)
		(width 0.20066)
		(layer "F.Cu")
		(net "M_A_CPU1_SB_CB<6>")
	)
	(segment
		(start 77.242162 -242.884706)
		(end 77.041502 -243.085366)
		(width 0.20066)
		(layer "F.Cu")
		(net "M_A_CPU1_SB_CB<6>")
	)
	(segment
		(start 85.539326 -241.635026)
		(end 85.444584 -241.635026)
		(width 0.088646)
		(layer "F.Cu")
		(net "M_A_CPU1_SB_CB<6>")
	)
	(segment
		(start 79.886302 -243.214906)
		(end 79.685642 -243.415566)
		(width 0.20066)
		(layer "F.Cu")
		(net "M_A_CPU1_SB_CB<6>")
	)
	(segment
		(start 66.677286 -240.507266)
		(end 66.39306 -240.507266)
		(width 0.20066)
		(layer "F.Cu")
		(net "M_A_CPU1_SB_CB<6>")
	)
	(segment
		(start 79.175102 -243.214906)
		(end 79.175102 -243.085366)
		(width 0.20066)
		(layer "F.Cu")
		(net "M_A_CPU1_SB_CB<6>")
	)
	(segment
		(start 79.175102 -243.085366)
		(end 78.974442 -242.884706)
		(width 0.20066)
		(layer "F.Cu")
		(net "M_A_CPU1_SB_CB<6>")
	)
	(segment
		(start 81.412588 -243.415566)
		(end 80.798162 -243.415566)
		(width 0.20066)
		(layer "F.Cu")
		(net "M_A_CPU1_SB_CB<6>")
	)
	(segment
		(start 80.396842 -242.884706)
		(end 80.086962 -242.884706)
		(width 0.20066)
		(layer "F.Cu")
		(net "M_A_CPU1_SB_CB<6>")
	)
	(segment
		(start 77.752702 -243.214906)
		(end 77.752702 -243.085366)
		(width 0.20066)
		(layer "F.Cu")
		(net "M_A_CPU1_SB_CB<6>")
	)
	(segment
		(start 59.692794 -241.092482)
		(end 59.8043 -241.092482)
		(width 0.101854)
		(layer "F.Cu")
		(net "M_A_CPU1_SB_CB<6>")
	)
	(segment
		(start 85.958426 -241.43208)
		(end 85.869526 -241.34318)
		(width 0.088646)
		(layer "F.Cu")
		(net "M_A_CPU1_SB_CB<6>")
	)
	(segment
		(start 62.072012 -241.09172)
		(end 62.21349 -241.09172)
		(width 0.101854)
		(layer "F.Cu")
		(net "M_A_CPU1_SB_CB<6>")
	)
	(segment
		(start 80.597502 -243.214906)
		(end 80.597502 -243.085366)
		(width 0.20066)
		(layer "F.Cu")
		(net "M_A_CPU1_SB_CB<6>")
	)
	(segment
		(start 76.330302 -243.214906)
		(end 76.330302 -243.085366)
		(width 0.20066)
		(layer "F.Cu")
		(net "M_A_CPU1_SB_CB<6>")
	)
	(segment
		(start 75.619102 -243.085366)
		(end 75.619102 -243.214906)
		(width 0.20066)
		(layer "F.Cu")
		(net "M_A_CPU1_SB_CB<6>")
	)
	(segment
		(start 78.974442 -242.884706)
		(end 78.664562 -242.884706)
		(width 0.20066)
		(layer "F.Cu")
		(net "M_A_CPU1_SB_CB<6>")
	)
	(segment
		(start 80.798162 -243.415566)
		(end 80.597502 -243.214906)
		(width 0.20066)
		(layer "F.Cu")
		(net "M_A_CPU1_SB_CB<6>")
	)
	(segment
		(start 74.890376 -243.415566)
		(end 73.613772 -242.138962)
		(width 0.20066)
		(layer "F.Cu")
		(net "M_A_CPU1_SB_CB<6>")
	)
	(segment
		(start 85.628226 -241.433858)
		(end 85.628226 -241.546126)
		(width 0.088646)
		(layer "F.Cu")
		(net "M_A_CPU1_SB_CB<6>")
	)
	(segment
		(start 71.154544 -241.120422)
		(end 67.290442 -241.120422)
		(width 0.20066)
		(layer "F.Cu")
		(net "M_A_CPU1_SB_CB<6>")
	)
	(segment
		(start 85.628226 -241.546126)
		(end 85.539326 -241.635026)
		(width 0.088646)
		(layer "F.Cu")
		(net "M_A_CPU1_SB_CB<6>")
	)
	(segment
		(start 75.619102 -243.214906)
		(end 75.418442 -243.415566)
		(width 0.20066)
		(layer "F.Cu")
		(net "M_A_CPU1_SB_CB<6>")
	)
	(segment
		(start 59.8043 -241.092482)
		(end 59.805062 -241.09172)
		(width 0.101854)
		(layer "F.Cu")
		(net "M_A_CPU1_SB_CB<6>")
	)
	(segment
		(start 59.23026 -240.666778)
		(end 59.655964 -241.092482)
		(width 0.20066)
		(layer "F.Cu")
		(net "M_A_CPU1_SB_CB<6>")
	)
	(segment
		(start 77.552042 -242.884706)
		(end 77.242162 -242.884706)
		(width 0.20066)
		(layer "F.Cu")
		(net "M_A_CPU1_SB_CB<6>")
	)
	(segment
		(start 62.796928 -240.483898)
		(end 63.256414 -240.483898)
		(width 0.20066)
		(layer "F.Cu")
		(net "M_A_CPU1_SB_CB<6>")
	)
	(segment
		(start 81.957672 -242.870482)
		(end 81.692496 -243.135658)
		(width 0.1016)
		(layer "F.Cu")
		(net "M_A_CPU1_SB_CB<6>")
	)
	(segment
		(start 63.256414 -240.483898)
		(end 63.439294 -240.666778)
		(width 0.20066)
		(layer "F.Cu")
		(net "M_A_CPU1_SB_CB<6>")
	)
	(segment
		(start 79.886302 -243.085366)
		(end 79.886302 -243.214906)
		(width 0.20066)
		(layer "F.Cu")
		(net "M_A_CPU1_SB_CB<6>")
	)
	(segment
		(start 85.444584 -241.635026)
		(end 85.138514 -241.527584)
		(width 0.088646)
		(layer "F.Cu")
		(net "M_A_CPU1_SB_CB<6>")
	)
	(segment
		(start 67.290442 -241.120422)
		(end 66.677286 -240.507266)
		(width 0.20066)
		(layer "F.Cu")
		(net "M_A_CPU1_SB_CB<6>")
	)
	(segment
		(start 79.685642 -243.415566)
		(end 79.375762 -243.415566)
		(width 0.20066)
		(layer "F.Cu")
		(net "M_A_CPU1_SB_CB<6>")
	)
	(segment
		(start 77.752702 -243.085366)
		(end 77.552042 -242.884706)
		(width 0.20066)
		(layer "F.Cu")
		(net "M_A_CPU1_SB_CB<6>")
	)
	(segment
		(start 80.086962 -242.884706)
		(end 79.886302 -243.085366)
		(width 0.20066)
		(layer "F.Cu")
		(net "M_A_CPU1_SB_CB<6>")
	)
	(segment
		(start 84.878672 -241.438938)
		(end 83.387692 -241.438938)
		(width 0.088646)
		(layer "F.Cu")
		(net "M_A_CPU1_SB_CB<6>")
	)
	(arc
		(start 85.138514 -241.527584)
		(mid 85.018895 -241.479324)
		(end 84.892642 -241.452908)
		(width 0.088646)
		(layer "F.Cu")
		(net "M_A_CPU1_SB_CB<6>")
	)
	(segment
		(start 84.098384 -241.118136)
		(end 83.276948 -241.118136)
		(width 0.088646)
		(layer "F.Cu")
		(net "M_A_CPU1_SB_CB<5>")
	)
	(segment
		(start 74.744072 -242.229386)
		(end 74.112628 -241.597942)
		(width 0.20066)
		(layer "F.Cu")
		(net "M_A_CPU1_SB_CB<5>")
	)
	(segment
		(start 85.325712 -241.203226)
		(end 84.378546 -241.21237)
		(width 0.088646)
		(layer "F.Cu")
		(net "M_A_CPU1_SB_CB<5>")
	)
	(segment
		(start 55.583328 -239.604042)
		(end 55.795672 -239.391698)
		(width 0.20066)
		(layer "F.Cu")
		(net "M_A_CPU1_SB_CB<5>")
	)
	(segment
		(start 55.01513 -240.118392)
		(end 55.382414 -240.118392)
		(width 0.20066)
		(layer "F.Cu")
		(net "M_A_CPU1_SB_CB<5>")
	)
	(segment
		(start 59.295538 -239.81664)
		(end 60.947046 -239.81664)
		(width 0.20066)
		(layer "F.Cu")
		(net "M_A_CPU1_SB_CB<5>")
	)
	(segment
		(start 83.123786 -241.271298)
		(end 82.165698 -242.229386)
		(width 0.101854)
		(layer "F.Cu")
		(net "M_A_CPU1_SB_CB<5>")
	)
	(segment
		(start 84.192618 -241.21237)
		(end 84.098384 -241.118136)
		(width 0.088646)
		(layer "F.Cu")
		(net "M_A_CPU1_SB_CB<5>")
	)
	(segment
		(start 58.79084 -239.391698)
		(end 58.870596 -239.391698)
		(width 0.20066)
		(layer "F.Cu")
		(net "M_A_CPU1_SB_CB<5>")
	)
	(segment
		(start 65.903348 -239.391698)
		(end 63.985394 -239.391698)
		(width 0.1016)
		(layer "F.Cu")
		(net "M_A_CPU1_SB_CB<5>")
	)
	(segment
		(start 55.382414 -240.118392)
		(end 55.583328 -239.917478)
		(width 0.20066)
		(layer "F.Cu")
		(net "M_A_CPU1_SB_CB<5>")
	)
	(segment
		(start 55.583328 -239.917478)
		(end 55.583328 -239.604042)
		(width 0.20066)
		(layer "F.Cu")
		(net "M_A_CPU1_SB_CB<5>")
	)
	(segment
		(start 54.713378 -239.81664)
		(end 55.01513 -240.118392)
		(width 0.20066)
		(layer "F.Cu")
		(net "M_A_CPU1_SB_CB<5>")
	)
	(segment
		(start 63.985394 -239.391698)
		(end 63.807594 -239.391698)
		(width 0.101854)
		(layer "F.Cu")
		(net "M_A_CPU1_SB_CB<5>")
	)
	(segment
		(start 63.533528 -239.391698)
		(end 62.90691 -240.018316)
		(width 0.20066)
		(layer "F.Cu")
		(net "M_A_CPU1_SB_CB<5>")
	)
	(segment
		(start 55.795672 -239.391698)
		(end 56.19369 -239.391698)
		(width 0.20066)
		(layer "F.Cu")
		(net "M_A_CPU1_SB_CB<5>")
	)
	(segment
		(start 83.276948 -241.118136)
		(end 83.123786 -241.271298)
		(width 0.088646)
		(layer "F.Cu")
		(net "M_A_CPU1_SB_CB<5>")
	)
	(segment
		(start 74.112628 -241.597942)
		(end 71.0184 -240.316004)
		(width 0.20066)
		(layer "F.Cu")
		(net "M_A_CPU1_SB_CB<5>")
	)
	(segment
		(start 66.308224 -239.391698)
		(end 65.903348 -239.391698)
		(width 0.101854)
		(layer "F.Cu")
		(net "M_A_CPU1_SB_CB<5>")
	)
	(segment
		(start 62.90691 -240.018316)
		(end 62.460378 -240.018316)
		(width 0.20066)
		(layer "F.Cu")
		(net "M_A_CPU1_SB_CB<5>")
	)
	(segment
		(start 62.258702 -239.81664)
		(end 60.947046 -239.81664)
		(width 0.20066)
		(layer "F.Cu")
		(net "M_A_CPU1_SB_CB<5>")
	)
	(segment
		(start 58.349134 -239.391698)
		(end 58.79084 -239.391698)
		(width 0.101854)
		(layer "F.Cu")
		(net "M_A_CPU1_SB_CB<5>")
	)
	(segment
		(start 63.807594 -239.391698)
		(end 63.533528 -239.391698)
		(width 0.20066)
		(layer "F.Cu")
		(net "M_A_CPU1_SB_CB<5>")
	)
	(segment
		(start 56.610758 -239.391698)
		(end 58.349134 -239.391698)
		(width 0.1016)
		(layer "F.Cu")
		(net "M_A_CPU1_SB_CB<5>")
	)
	(segment
		(start 66.583306 -239.391698)
		(end 66.308224 -239.391698)
		(width 0.20066)
		(layer "F.Cu")
		(net "M_A_CPU1_SB_CB<5>")
	)
	(segment
		(start 67.39382 -240.316004)
		(end 66.792348 -239.714532)
		(width 0.20066)
		(layer "F.Cu")
		(net "M_A_CPU1_SB_CB<5>")
	)
	(segment
		(start 58.870596 -239.391698)
		(end 59.295538 -239.81664)
		(width 0.20066)
		(layer "F.Cu")
		(net "M_A_CPU1_SB_CB<5>")
	)
	(segment
		(start 71.0184 -240.316004)
		(end 67.39382 -240.316004)
		(width 0.20066)
		(layer "F.Cu")
		(net "M_A_CPU1_SB_CB<5>")
	)
	(segment
		(start 56.19369 -239.391698)
		(end 56.610758 -239.391698)
		(width 0.101854)
		(layer "F.Cu")
		(net "M_A_CPU1_SB_CB<5>")
	)
	(segment
		(start 53.403246 -239.81664)
		(end 54.713378 -239.81664)
		(width 0.20066)
		(layer "F.Cu")
		(net "M_A_CPU1_SB_CB<5>")
	)
	(segment
		(start 62.460378 -240.018316)
		(end 62.258702 -239.81664)
		(width 0.20066)
		(layer "F.Cu")
		(net "M_A_CPU1_SB_CB<5>")
	)
	(segment
		(start 82.165698 -242.229386)
		(end 81.692496 -242.229386)
		(width 0.1016)
		(layer "F.Cu")
		(net "M_A_CPU1_SB_CB<5>")
	)
	(segment
		(start 84.378546 -241.21237)
		(end 84.192618 -241.21237)
		(width 0.088646)
		(layer "F.Cu")
		(net "M_A_CPU1_SB_CB<5>")
	)
	(segment
		(start 81.692496 -242.229386)
		(end 74.744072 -242.229386)
		(width 0.20066)
		(layer "F.Cu")
		(net "M_A_CPU1_SB_CB<5>")
	)
	(segment
		(start 66.792348 -239.60074)
		(end 66.583306 -239.391698)
		(width 0.20066)
		(layer "F.Cu")
		(net "M_A_CPU1_SB_CB<5>")
	)
	(segment
		(start 66.792348 -239.714532)
		(end 66.792348 -239.60074)
		(width 0.20066)
		(layer "F.Cu")
		(net "M_A_CPU1_SB_CB<5>")
	)
	(segment
		(start 67.073018 -241.817906)
		(end 66.346832 -241.09172)
		(width 0.20066)
		(layer "F.Cu")
		(net "M_A_CPU1_SB_CB<4>")
	)
	(segment
		(start 81.692496 -244.055138)
		(end 74.522838 -244.055138)
		(width 0.20066)
		(layer "F.Cu")
		(net "M_A_CPU1_SB_CB<4>")
	)
	(segment
		(start 66.16446 -241.09172)
		(end 64.185292 -241.09172)
		(width 0.1016)
		(layer "F.Cu")
		(net "M_A_CPU1_SB_CB<4>")
	)
	(segment
		(start 82.190844 -243.067332)
		(end 82.190844 -243.772436)
		(width 0.1016)
		(layer "F.Cu")
		(net "M_A_CPU1_SB_CB<4>")
	)
	(segment
		(start 55.583328 -241.615976)
		(end 55.382414 -241.81689)
		(width 0.20066)
		(layer "F.Cu")
		(net "M_A_CPU1_SB_CB<4>")
	)
	(segment
		(start 71.132192 -241.817906)
		(end 67.073018 -241.817906)
		(width 0.20066)
		(layer "F.Cu")
		(net "M_A_CPU1_SB_CB<4>")
	)
	(segment
		(start 56.610758 -241.09172)
		(end 56.24576 -241.09172)
		(width 0.101854)
		(layer "F.Cu")
		(net "M_A_CPU1_SB_CB<4>")
	)
	(segment
		(start 58.907934 -241.09172)
		(end 58.786522 -241.09172)
		(width 0.20066)
		(layer "F.Cu")
		(net "M_A_CPU1_SB_CB<4>")
	)
	(segment
		(start 55.583328 -241.260122)
		(end 55.583328 -241.615976)
		(width 0.20066)
		(layer "F.Cu")
		(net "M_A_CPU1_SB_CB<4>")
	)
	(segment
		(start 84.946998 -241.680238)
		(end 83.577938 -241.680238)
		(width 0.088646)
		(layer "F.Cu")
		(net "M_A_CPU1_SB_CB<4>")
	)
	(segment
		(start 82.190844 -243.772436)
		(end 81.908142 -244.055138)
		(width 0.1016)
		(layer "F.Cu")
		(net "M_A_CPU1_SB_CB<4>")
	)
	(segment
		(start 60.892944 -241.570764)
		(end 59.386978 -241.570764)
		(width 0.20066)
		(layer "F.Cu")
		(net "M_A_CPU1_SB_CB<4>")
	)
	(segment
		(start 58.786522 -241.09172)
		(end 58.349134 -241.09172)
		(width 0.101854)
		(layer "F.Cu")
		(net "M_A_CPU1_SB_CB<4>")
	)
	(segment
		(start 81.908142 -244.055138)
		(end 81.692496 -244.055138)
		(width 0.1016)
		(layer "F.Cu")
		(net "M_A_CPU1_SB_CB<4>")
	)
	(segment
		(start 59.386978 -241.570764)
		(end 58.907934 -241.09172)
		(width 0.20066)
		(layer "F.Cu")
		(net "M_A_CPU1_SB_CB<4>")
	)
	(segment
		(start 63.795656 -241.09172)
		(end 63.252096 -241.09172)
		(width 0.20066)
		(layer "F.Cu")
		(net "M_A_CPU1_SB_CB<4>")
	)
	(segment
		(start 58.349134 -241.09172)
		(end 56.610758 -241.09172)
		(width 0.1016)
		(layer "F.Cu")
		(net "M_A_CPU1_SB_CB<4>")
	)
	(segment
		(start 85.43544 -241.920014)
		(end 85.086444 -241.717576)
		(width 0.088646)
		(layer "F.Cu")
		(net "M_A_CPU1_SB_CB<4>")
	)
	(segment
		(start 83.517232 -241.740944)
		(end 82.190844 -243.067332)
		(width 0.1016)
		(layer "F.Cu")
		(net "M_A_CPU1_SB_CB<4>")
	)
	(segment
		(start 60.947046 -241.516662)
		(end 60.892944 -241.570764)
		(width 0.20066)
		(layer "F.Cu")
		(net "M_A_CPU1_SB_CB<4>")
	)
	(segment
		(start 63.252096 -241.09172)
		(end 62.827154 -241.516662)
		(width 0.20066)
		(layer "F.Cu")
		(net "M_A_CPU1_SB_CB<4>")
	)
	(segment
		(start 55.013606 -241.81689)
		(end 54.713378 -241.516662)
		(width 0.20066)
		(layer "F.Cu")
		(net "M_A_CPU1_SB_CB<4>")
	)
	(segment
		(start 56.24576 -241.09172)
		(end 55.75173 -241.09172)
		(width 0.20066)
		(layer "F.Cu")
		(net "M_A_CPU1_SB_CB<4>")
	)
	(segment
		(start 55.382414 -241.81689)
		(end 55.013606 -241.81689)
		(width 0.20066)
		(layer "F.Cu")
		(net "M_A_CPU1_SB_CB<4>")
	)
	(segment
		(start 54.713378 -241.516662)
		(end 53.403246 -241.516662)
		(width 0.20066)
		(layer "F.Cu")
		(net "M_A_CPU1_SB_CB<4>")
	)
	(segment
		(start 83.577938 -241.680238)
		(end 83.517232 -241.740944)
		(width 0.088646)
		(layer "F.Cu")
		(net "M_A_CPU1_SB_CB<4>")
	)
	(segment
		(start 64.185292 -241.09172)
		(end 63.795656 -241.09172)
		(width 0.101854)
		(layer "F.Cu")
		(net "M_A_CPU1_SB_CB<4>")
	)
	(segment
		(start 66.30416 -241.09172)
		(end 66.16446 -241.09172)
		(width 0.101854)
		(layer "F.Cu")
		(net "M_A_CPU1_SB_CB<4>")
	)
	(segment
		(start 62.827154 -241.516662)
		(end 60.947046 -241.516662)
		(width 0.20066)
		(layer "F.Cu")
		(net "M_A_CPU1_SB_CB<4>")
	)
	(segment
		(start 66.346832 -241.09172)
		(end 66.30416 -241.09172)
		(width 0.20066)
		(layer "F.Cu")
		(net "M_A_CPU1_SB_CB<4>")
	)
	(segment
		(start 73.101708 -242.634008)
		(end 71.132192 -241.817906)
		(width 0.20066)
		(layer "F.Cu")
		(net "M_A_CPU1_SB_CB<4>")
	)
	(segment
		(start 74.522838 -244.055138)
		(end 73.101708 -242.634008)
		(width 0.20066)
		(layer "F.Cu")
		(net "M_A_CPU1_SB_CB<4>")
	)
	(segment
		(start 55.75173 -241.09172)
		(end 55.583328 -241.260122)
		(width 0.20066)
		(layer "F.Cu")
		(net "M_A_CPU1_SB_CB<4>")
	)
	(arc
		(start 85.086444 -241.717576)
		(mid 85.01918 -241.689717)
		(end 84.946998 -241.680238)
		(width 0.088646)
		(layer "F.Cu")
		(net "M_A_CPU1_SB_CB<4>")
	)
	(arc
		(start 85.795866 -242.017042)
		(mid 85.609252 -241.992318)
		(end 85.43544 -241.920014)
		(width 0.088646)
		(layer "F.Cu")
		(net "M_A_CPU1_SB_CB<4>")
	)
	(segment
		(start 59.107832 -232.955846)
		(end 59.593734 -233.441748)
		(width 0.20066)
		(layer "F.Cu")
		(net "M_A_CPU1_SB_CB<3>")
	)
	(segment
		(start 79.809594 -236.086142)
		(end 80.010254 -236.286802)
		(width 0.20066)
		(layer "F.Cu")
		(net "M_A_CPU1_SB_CB<3>")
	)
	(segment
		(start 79.809594 -235.921804)
		(end 79.809594 -236.086142)
		(width 0.20066)
		(layer "F.Cu")
		(net "M_A_CPU1_SB_CB<3>")
	)
	(segment
		(start 80.010254 -236.286802)
		(end 80.387444 -236.286802)
		(width 0.20066)
		(layer "F.Cu")
		(net "M_A_CPU1_SB_CB<3>")
	)
	(segment
		(start 62.542674 -233.441748)
		(end 62.669928 -233.314494)
		(width 0.20066)
		(layer "F.Cu")
		(net "M_A_CPU1_SB_CB<3>")
	)
	(segment
		(start 83.84159 -237.899448)
		(end 84.207096 -237.899448)
		(width 0.1016)
		(layer "F.Cu")
		(net "M_A_CPU1_SB_CB<3>")
	)
	(segment
		(start 86.425024 -238.761524)
		(end 86.735666 -238.761524)
		(width 0.088646)
		(layer "F.Cu")
		(net "M_A_CPU1_SB_CB<3>")
	)
	(segment
		(start 59.593734 -233.441748)
		(end 59.698382 -233.441748)
		(width 0.20066)
		(layer "F.Cu")
		(net "M_A_CPU1_SB_CB<3>")
	)
	(segment
		(start 66.331338 -233.016806)
		(end 66.61277 -232.735374)
		(width 0.20066)
		(layer "F.Cu")
		(net "M_A_CPU1_SB_CB<3>")
	)
	(segment
		(start 76.163424 -233.99877)
		(end 77.269086 -235.104432)
		(width 0.20066)
		(layer "F.Cu")
		(net "M_A_CPU1_SB_CB<3>")
	)
	(segment
		(start 80.387444 -236.286802)
		(end 80.579214 -236.286802)
		(width 0.1016)
		(layer "F.Cu")
		(net "M_A_CPU1_SB_CB<3>")
	)
	(segment
		(start 66.61277 -232.735374)
		(end 67.22745 -232.735374)
		(width 0.20066)
		(layer "F.Cu")
		(net "M_A_CPU1_SB_CB<3>")
	)
	(segment
		(start 58.37809 -233.016806)
		(end 58.43905 -232.955846)
		(width 0.20066)
		(layer "F.Cu")
		(net "M_A_CPU1_SB_CB<3>")
	)
	(segment
		(start 79.608934 -235.721144)
		(end 79.809594 -235.921804)
		(width 0.20066)
		(layer "F.Cu")
		(net "M_A_CPU1_SB_CB<3>")
	)
	(segment
		(start 78.391766 -234.987846)
		(end 78.391766 -235.27131)
		(width 0.20066)
		(layer "F.Cu")
		(net "M_A_CPU1_SB_CB<3>")
	)
	(segment
		(start 62.967362 -232.795064)
		(end 63.438024 -232.795064)
		(width 0.20066)
		(layer "F.Cu")
		(net "M_A_CPU1_SB_CB<3>")
	)
	(segment
		(start 80.579214 -236.286802)
		(end 80.889602 -236.59719)
		(width 0.1016)
		(layer "F.Cu")
		(net "M_A_CPU1_SB_CB<3>")
	)
	(segment
		(start 84.207096 -237.899448)
		(end 84.747354 -237.899448)
		(width 0.088646)
		(layer "F.Cu")
		(net "M_A_CPU1_SB_CB<3>")
	)
	(segment
		(start 79.098394 -236.086142)
		(end 79.098394 -235.921804)
		(width 0.20066)
		(layer "F.Cu")
		(net "M_A_CPU1_SB_CB<3>")
	)
	(segment
		(start 77.55255 -235.104432)
		(end 77.888846 -234.76839)
		(width 0.20066)
		(layer "F.Cu")
		(net "M_A_CPU1_SB_CB<3>")
	)
	(segment
		(start 67.22745 -232.735374)
		(end 68.490846 -233.99877)
		(width 0.20066)
		(layer "F.Cu")
		(net "M_A_CPU1_SB_CB<3>")
	)
	(segment
		(start 78.17231 -234.76839)
		(end 78.391766 -234.987846)
		(width 0.20066)
		(layer "F.Cu")
		(net "M_A_CPU1_SB_CB<3>")
	)
	(segment
		(start 62.206886 -233.441748)
		(end 62.542674 -233.441748)
		(width 0.20066)
		(layer "F.Cu")
		(net "M_A_CPU1_SB_CB<3>")
	)
	(segment
		(start 77.888846 -234.76839)
		(end 78.17231 -234.76839)
		(width 0.20066)
		(layer "F.Cu")
		(net "M_A_CPU1_SB_CB<3>")
	)
	(segment
		(start 63.659766 -233.016806)
		(end 65.047114 -233.016806)
		(width 0.20066)
		(layer "F.Cu")
		(net "M_A_CPU1_SB_CB<3>")
	)
	(segment
		(start 78.391766 -235.27131)
		(end 78.05547 -235.607352)
		(width 0.20066)
		(layer "F.Cu")
		(net "M_A_CPU1_SB_CB<3>")
	)
	(segment
		(start 78.05547 -235.890816)
		(end 78.451456 -236.286802)
		(width 0.20066)
		(layer "F.Cu")
		(net "M_A_CPU1_SB_CB<3>")
	)
	(segment
		(start 57.503314 -233.016806)
		(end 58.37809 -233.016806)
		(width 0.20066)
		(layer "F.Cu")
		(net "M_A_CPU1_SB_CB<3>")
	)
	(segment
		(start 80.889602 -236.801406)
		(end 81.884012 -237.795816)
		(width 0.1016)
		(layer "F.Cu")
		(net "M_A_CPU1_SB_CB<3>")
	)
	(segment
		(start 77.269086 -235.104432)
		(end 77.55255 -235.104432)
		(width 0.20066)
		(layer "F.Cu")
		(net "M_A_CPU1_SB_CB<3>")
	)
	(segment
		(start 79.299054 -235.721144)
		(end 79.608934 -235.721144)
		(width 0.20066)
		(layer "F.Cu")
		(net "M_A_CPU1_SB_CB<3>")
	)
	(segment
		(start 65.047114 -233.016806)
		(end 66.331338 -233.016806)
		(width 0.20066)
		(layer "F.Cu")
		(net "M_A_CPU1_SB_CB<3>")
	)
	(segment
		(start 62.072012 -233.441748)
		(end 62.206886 -233.441748)
		(width 0.101854)
		(layer "F.Cu")
		(net "M_A_CPU1_SB_CB<3>")
	)
	(segment
		(start 62.669928 -233.092498)
		(end 62.967362 -232.795064)
		(width 0.20066)
		(layer "F.Cu")
		(net "M_A_CPU1_SB_CB<3>")
	)
	(segment
		(start 86.357206 -238.693706)
		(end 86.425024 -238.761524)
		(width 0.088646)
		(layer "F.Cu")
		(net "M_A_CPU1_SB_CB<3>")
	)
	(segment
		(start 86.068154 -238.26597)
		(end 86.078568 -238.272066)
		(width 0.088646)
		(layer "F.Cu")
		(net "M_A_CPU1_SB_CB<3>")
	)
	(segment
		(start 83.737958 -237.795816)
		(end 83.84159 -237.899448)
		(width 0.1016)
		(layer "F.Cu")
		(net "M_A_CPU1_SB_CB<3>")
	)
	(segment
		(start 81.884012 -237.795816)
		(end 83.737958 -237.795816)
		(width 0.1016)
		(layer "F.Cu")
		(net "M_A_CPU1_SB_CB<3>")
	)
	(segment
		(start 78.451456 -236.286802)
		(end 78.897734 -236.286802)
		(width 0.20066)
		(layer "F.Cu")
		(net "M_A_CPU1_SB_CB<3>")
	)
	(segment
		(start 80.889602 -236.59719)
		(end 80.889602 -236.801406)
		(width 0.1016)
		(layer "F.Cu")
		(net "M_A_CPU1_SB_CB<3>")
	)
	(segment
		(start 78.897734 -236.286802)
		(end 79.098394 -236.086142)
		(width 0.20066)
		(layer "F.Cu")
		(net "M_A_CPU1_SB_CB<3>")
	)
	(segment
		(start 79.098394 -235.921804)
		(end 79.299054 -235.721144)
		(width 0.20066)
		(layer "F.Cu")
		(net "M_A_CPU1_SB_CB<3>")
	)
	(segment
		(start 84.747354 -237.899448)
		(end 85.060536 -238.21263)
		(width 0.088646)
		(layer "F.Cu")
		(net "M_A_CPU1_SB_CB<3>")
	)
	(segment
		(start 63.438024 -232.795064)
		(end 63.659766 -233.016806)
		(width 0.20066)
		(layer "F.Cu")
		(net "M_A_CPU1_SB_CB<3>")
	)
	(segment
		(start 59.698382 -233.441748)
		(end 59.887612 -233.441748)
		(width 0.101854)
		(layer "F.Cu")
		(net "M_A_CPU1_SB_CB<3>")
	)
	(segment
		(start 58.43905 -232.955846)
		(end 59.107832 -232.955846)
		(width 0.20066)
		(layer "F.Cu")
		(net "M_A_CPU1_SB_CB<3>")
	)
	(segment
		(start 62.669928 -233.314494)
		(end 62.669928 -233.092498)
		(width 0.20066)
		(layer "F.Cu")
		(net "M_A_CPU1_SB_CB<3>")
	)
	(segment
		(start 68.490846 -233.99877)
		(end 76.163424 -233.99877)
		(width 0.20066)
		(layer "F.Cu")
		(net "M_A_CPU1_SB_CB<3>")
	)
	(segment
		(start 59.887612 -233.441748)
		(end 62.072012 -233.441748)
		(width 0.1016)
		(layer "F.Cu")
		(net "M_A_CPU1_SB_CB<3>")
	)
	(segment
		(start 78.05547 -235.607352)
		(end 78.05547 -235.890816)
		(width 0.20066)
		(layer "F.Cu")
		(net "M_A_CPU1_SB_CB<3>")
	)
	(arc
		(start 85.060536 -238.21263)
		(mid 85.097584 -238.244893)
		(end 85.138514 -238.272066)
		(width 0.088646)
		(layer "F.Cu")
		(net "M_A_CPU1_SB_CB<3>")
	)
	(arc
		(start 85.51291 -238.272066)
		(mid 85.789723 -238.196196)
		(end 86.068154 -238.26597)
		(width 0.088646)
		(layer "F.Cu")
		(net "M_A_CPU1_SB_CB<3>")
	)
	(arc
		(start 86.078568 -238.272066)
		(mid 86.267615 -238.450015)
		(end 86.357206 -238.693706)
		(width 0.088646)
		(layer "F.Cu")
		(net "M_A_CPU1_SB_CB<3>")
	)
	(arc
		(start 85.138514 -238.272066)
		(mid 85.325712 -238.322209)
		(end 85.51291 -238.272066)
		(width 0.088646)
		(layer "F.Cu")
		(net "M_A_CPU1_SB_CB<3>")
	)
	(segment
		(start 84.796884 -239.421162)
		(end 84.196174 -239.421162)
		(width 0.088646)
		(layer "F.Cu")
		(net "M_A_CPU1_SB_CB<2>")
	)
	(segment
		(start 81.630774 -238.405416)
		(end 80.792066 -237.566708)
		(width 0.1016)
		(layer "F.Cu")
		(net "M_A_CPU1_SB_CB<2>")
	)
	(segment
		(start 73.214992 -235.737146)
		(end 73.014332 -235.937806)
		(width 0.20066)
		(layer "F.Cu")
		(net "M_A_CPU1_SB_CB<2>")
	)
	(segment
		(start 80.555084 -237.566708)
		(end 77.735684 -237.566708)
		(width 0.20066)
		(layer "F.Cu")
		(net "M_A_CPU1_SB_CB<2>")
	)
	(segment
		(start 62.669928 -234.660694)
		(end 62.83579 -234.494832)
		(width 0.20066)
		(layer "F.Cu")
		(net "M_A_CPU1_SB_CB<2>")
	)
	(segment
		(start 71.792592 -235.737146)
		(end 71.591932 -235.937806)
		(width 0.20066)
		(layer "F.Cu")
		(net "M_A_CPU1_SB_CB<2>")
	)
	(segment
		(start 70.570852 -235.439458)
		(end 70.370192 -235.640118)
		(width 0.20066)
		(layer "F.Cu")
		(net "M_A_CPU1_SB_CB<2>")
	)
	(segment
		(start 59.913012 -235.141516)
		(end 62.072012 -235.141516)
		(width 0.1016)
		(layer "F.Cu")
		(net "M_A_CPU1_SB_CB<2>")
	)
	(segment
		(start 74.637392 -235.640118)
		(end 74.637392 -235.737146)
		(width 0.20066)
		(layer "F.Cu")
		(net "M_A_CPU1_SB_CB<2>")
	)
	(segment
		(start 71.591932 -235.937806)
		(end 71.282052 -235.937806)
		(width 0.20066)
		(layer "F.Cu")
		(net "M_A_CPU1_SB_CB<2>")
	)
	(segment
		(start 74.436732 -235.937806)
		(end 74.126852 -235.937806)
		(width 0.20066)
		(layer "F.Cu")
		(net "M_A_CPU1_SB_CB<2>")
	)
	(segment
		(start 84.076794 -239.301782)
		(end 83.978242 -239.064038)
		(width 0.088646)
		(layer "F.Cu")
		(net "M_A_CPU1_SB_CB<2>")
	)
	(segment
		(start 87.205312 -239.57534)
		(end 86.500716 -239.168432)
		(width 0.088646)
		(layer "F.Cu")
		(net "M_A_CPU1_SB_CB<2>")
	)
	(segment
		(start 74.838052 -235.439458)
		(end 74.637392 -235.640118)
		(width 0.20066)
		(layer "F.Cu")
		(net "M_A_CPU1_SB_CB<2>")
	)
	(segment
		(start 72.503792 -235.640118)
		(end 72.303132 -235.439458)
		(width 0.20066)
		(layer "F.Cu")
		(net "M_A_CPU1_SB_CB<2>")
	)
	(segment
		(start 62.542674 -235.141516)
		(end 62.669928 -235.014262)
		(width 0.20066)
		(layer "F.Cu")
		(net "M_A_CPU1_SB_CB<2>")
	)
	(segment
		(start 69.458332 -235.439458)
		(end 67.986402 -235.439458)
		(width 0.20066)
		(layer "F.Cu")
		(net "M_A_CPU1_SB_CB<2>")
	)
	(segment
		(start 73.926192 -235.640118)
		(end 73.725532 -235.439458)
		(width 0.20066)
		(layer "F.Cu")
		(net "M_A_CPU1_SB_CB<2>")
	)
	(segment
		(start 77.735684 -237.566708)
		(end 75.608434 -235.439458)
		(width 0.20066)
		(layer "F.Cu")
		(net "M_A_CPU1_SB_CB<2>")
	)
	(segment
		(start 57.503314 -234.716574)
		(end 59.182508 -234.716574)
		(width 0.20066)
		(layer "F.Cu")
		(net "M_A_CPU1_SB_CB<2>")
	)
	(segment
		(start 71.081392 -235.737146)
		(end 71.081392 -235.640118)
		(width 0.20066)
		(layer "F.Cu")
		(net "M_A_CPU1_SB_CB<2>")
	)
	(segment
		(start 74.126852 -235.937806)
		(end 73.926192 -235.737146)
		(width 0.20066)
		(layer "F.Cu")
		(net "M_A_CPU1_SB_CB<2>")
	)
	(segment
		(start 62.83579 -234.494832)
		(end 63.329312 -234.494832)
		(width 0.20066)
		(layer "F.Cu")
		(net "M_A_CPU1_SB_CB<2>")
	)
	(segment
		(start 66.672968 -234.453176)
		(end 66.40957 -234.716574)
		(width 0.20066)
		(layer "F.Cu")
		(net "M_A_CPU1_SB_CB<2>")
	)
	(segment
		(start 67.00012 -234.453176)
		(end 66.672968 -234.453176)
		(width 0.20066)
		(layer "F.Cu")
		(net "M_A_CPU1_SB_CB<2>")
	)
	(segment
		(start 72.503792 -235.737146)
		(end 72.503792 -235.640118)
		(width 0.20066)
		(layer "F.Cu")
		(net "M_A_CPU1_SB_CB<2>")
	)
	(segment
		(start 59.182508 -234.716574)
		(end 59.60745 -235.141516)
		(width 0.20066)
		(layer "F.Cu")
		(net "M_A_CPU1_SB_CB<2>")
	)
	(segment
		(start 71.081392 -235.640118)
		(end 70.880732 -235.439458)
		(width 0.20066)
		(layer "F.Cu")
		(net "M_A_CPU1_SB_CB<2>")
	)
	(segment
		(start 70.370192 -235.640118)
		(end 70.370192 -235.737146)
		(width 0.20066)
		(layer "F.Cu")
		(net "M_A_CPU1_SB_CB<2>")
	)
	(segment
		(start 62.669928 -235.014262)
		(end 62.669928 -234.660694)
		(width 0.20066)
		(layer "F.Cu")
		(net "M_A_CPU1_SB_CB<2>")
	)
	(segment
		(start 83.31962 -238.405416)
		(end 81.630774 -238.405416)
		(width 0.1016)
		(layer "F.Cu")
		(net "M_A_CPU1_SB_CB<2>")
	)
	(segment
		(start 73.725532 -235.439458)
		(end 73.415652 -235.439458)
		(width 0.20066)
		(layer "F.Cu")
		(net "M_A_CPU1_SB_CB<2>")
	)
	(segment
		(start 67.986402 -235.439458)
		(end 67.00012 -234.453176)
		(width 0.20066)
		(layer "F.Cu")
		(net "M_A_CPU1_SB_CB<2>")
	)
	(segment
		(start 73.014332 -235.937806)
		(end 72.704452 -235.937806)
		(width 0.20066)
		(layer "F.Cu")
		(net "M_A_CPU1_SB_CB<2>")
	)
	(segment
		(start 69.658992 -235.737146)
		(end 69.658992 -235.640118)
		(width 0.20066)
		(layer "F.Cu")
		(net "M_A_CPU1_SB_CB<2>")
	)
	(segment
		(start 59.60745 -235.141516)
		(end 59.684412 -235.141516)
		(width 0.20066)
		(layer "F.Cu")
		(net "M_A_CPU1_SB_CB<2>")
	)
	(segment
		(start 71.792592 -235.640118)
		(end 71.792592 -235.737146)
		(width 0.20066)
		(layer "F.Cu")
		(net "M_A_CPU1_SB_CB<2>")
	)
	(segment
		(start 69.658992 -235.640118)
		(end 69.458332 -235.439458)
		(width 0.20066)
		(layer "F.Cu")
		(net "M_A_CPU1_SB_CB<2>")
	)
	(segment
		(start 73.415652 -235.439458)
		(end 73.214992 -235.640118)
		(width 0.20066)
		(layer "F.Cu")
		(net "M_A_CPU1_SB_CB<2>")
	)
	(segment
		(start 62.213236 -235.141516)
		(end 62.542674 -235.141516)
		(width 0.20066)
		(layer "F.Cu")
		(net "M_A_CPU1_SB_CB<2>")
	)
	(segment
		(start 69.859652 -235.937806)
		(end 69.658992 -235.737146)
		(width 0.20066)
		(layer "F.Cu")
		(net "M_A_CPU1_SB_CB<2>")
	)
	(segment
		(start 71.282052 -235.937806)
		(end 71.081392 -235.737146)
		(width 0.20066)
		(layer "F.Cu")
		(net "M_A_CPU1_SB_CB<2>")
	)
	(segment
		(start 59.684412 -235.141516)
		(end 59.913012 -235.141516)
		(width 0.101854)
		(layer "F.Cu")
		(net "M_A_CPU1_SB_CB<2>")
	)
	(segment
		(start 83.978242 -239.064038)
		(end 83.896454 -238.98225)
		(width 0.088646)
		(layer "F.Cu")
		(net "M_A_CPU1_SB_CB<2>")
	)
	(segment
		(start 73.926192 -235.737146)
		(end 73.926192 -235.640118)
		(width 0.20066)
		(layer "F.Cu")
		(net "M_A_CPU1_SB_CB<2>")
	)
	(segment
		(start 84.196174 -239.421162)
		(end 84.076794 -239.301782)
		(width 0.088646)
		(layer "F.Cu")
		(net "M_A_CPU1_SB_CB<2>")
	)
	(segment
		(start 80.792066 -237.566708)
		(end 80.555084 -237.566708)
		(width 0.1016)
		(layer "F.Cu")
		(net "M_A_CPU1_SB_CB<2>")
	)
	(segment
		(start 75.608434 -235.439458)
		(end 74.838052 -235.439458)
		(width 0.20066)
		(layer "F.Cu")
		(net "M_A_CPU1_SB_CB<2>")
	)
	(segment
		(start 74.637392 -235.737146)
		(end 74.436732 -235.937806)
		(width 0.20066)
		(layer "F.Cu")
		(net "M_A_CPU1_SB_CB<2>")
	)
	(segment
		(start 66.40957 -234.716574)
		(end 65.047114 -234.716574)
		(width 0.20066)
		(layer "F.Cu")
		(net "M_A_CPU1_SB_CB<2>")
	)
	(segment
		(start 62.072012 -235.141516)
		(end 62.213236 -235.141516)
		(width 0.101854)
		(layer "F.Cu")
		(net "M_A_CPU1_SB_CB<2>")
	)
	(segment
		(start 70.880732 -235.439458)
		(end 70.570852 -235.439458)
		(width 0.20066)
		(layer "F.Cu")
		(net "M_A_CPU1_SB_CB<2>")
	)
	(segment
		(start 63.329312 -234.494832)
		(end 63.551054 -234.716574)
		(width 0.20066)
		(layer "F.Cu")
		(net "M_A_CPU1_SB_CB<2>")
	)
	(segment
		(start 72.704452 -235.937806)
		(end 72.503792 -235.737146)
		(width 0.20066)
		(layer "F.Cu")
		(net "M_A_CPU1_SB_CB<2>")
	)
	(segment
		(start 71.993252 -235.439458)
		(end 71.792592 -235.640118)
		(width 0.20066)
		(layer "F.Cu")
		(net "M_A_CPU1_SB_CB<2>")
	)
	(segment
		(start 83.896454 -238.98225)
		(end 83.31962 -238.405416)
		(width 0.101854)
		(layer "F.Cu")
		(net "M_A_CPU1_SB_CB<2>")
	)
	(segment
		(start 70.169532 -235.937806)
		(end 69.859652 -235.937806)
		(width 0.20066)
		(layer "F.Cu")
		(net "M_A_CPU1_SB_CB<2>")
	)
	(segment
		(start 84.972144 -239.245902)
		(end 84.796884 -239.421162)
		(width 0.088646)
		(layer "F.Cu")
		(net "M_A_CPU1_SB_CB<2>")
	)
	(segment
		(start 63.551054 -234.716574)
		(end 65.047114 -234.716574)
		(width 0.20066)
		(layer "F.Cu")
		(net "M_A_CPU1_SB_CB<2>")
	)
	(segment
		(start 73.214992 -235.640118)
		(end 73.214992 -235.737146)
		(width 0.20066)
		(layer "F.Cu")
		(net "M_A_CPU1_SB_CB<2>")
	)
	(segment
		(start 70.370192 -235.737146)
		(end 70.169532 -235.937806)
		(width 0.20066)
		(layer "F.Cu")
		(net "M_A_CPU1_SB_CB<2>")
	)
	(segment
		(start 72.303132 -235.439458)
		(end 71.993252 -235.439458)
		(width 0.20066)
		(layer "F.Cu")
		(net "M_A_CPU1_SB_CB<2>")
	)
	(arc
		(start 85.560916 -239.168432)
		(mid 85.253333 -239.107061)
		(end 84.972144 -239.245902)
		(width 0.088646)
		(layer "F.Cu")
		(net "M_A_CPU1_SB_CB<2>")
	)
	(arc
		(start 86.030816 -239.168432)
		(mid 85.795866 -239.231392)
		(end 85.560916 -239.168432)
		(width 0.088646)
		(layer "F.Cu")
		(net "M_A_CPU1_SB_CB<2>")
	)
	(arc
		(start 86.500716 -239.168432)
		(mid 86.265766 -239.105472)
		(end 86.030816 -239.168432)
		(width 0.088646)
		(layer "F.Cu")
		(net "M_A_CPU1_SB_CB<2>")
	)
	(segment
		(start 55.744364 -233.903012)
		(end 55.744364 -233.61142)
		(width 0.20066)
		(layer "F.Cu")
		(net "M_A_CPU1_SB_CB<1>")
	)
	(segment
		(start 56.245506 -233.441748)
		(end 56.610758 -233.441748)
		(width 0.101854)
		(layer "F.Cu")
		(net "M_A_CPU1_SB_CB<1>")
	)
	(segment
		(start 75.71867 -234.6452)
		(end 68.11899 -234.6452)
		(width 0.20066)
		(layer "F.Cu")
		(net "M_A_CPU1_SB_CB<1>")
	)
	(segment
		(start 84.783168 -238.204502)
		(end 84.207096 -238.204502)
		(width 0.088646)
		(layer "F.Cu")
		(net "M_A_CPU1_SB_CB<1>")
	)
	(segment
		(start 59.370722 -233.916728)
		(end 60.073032 -233.916728)
		(width 0.20066)
		(layer "F.Cu")
		(net "M_A_CPU1_SB_CB<1>")
	)
	(segment
		(start 58.895742 -233.441748)
		(end 59.370722 -233.916728)
		(width 0.20066)
		(layer "F.Cu")
		(net "M_A_CPU1_SB_CB<1>")
	)
	(segment
		(start 58.349134 -233.441748)
		(end 58.768234 -233.441748)
		(width 0.101854)
		(layer "F.Cu")
		(net "M_A_CPU1_SB_CB<1>")
	)
	(segment
		(start 84.925916 -238.347504)
		(end 84.783168 -238.204502)
		(width 0.088646)
		(layer "F.Cu")
		(net "M_A_CPU1_SB_CB<1>")
	)
	(segment
		(start 54.960266 -233.86669)
		(end 55.197248 -234.103672)
		(width 0.20066)
		(layer "F.Cu")
		(net "M_A_CPU1_SB_CB<1>")
	)
	(segment
		(start 63.99403 -233.441748)
		(end 63.775336 -233.441748)
		(width 0.101854)
		(layer "F.Cu")
		(net "M_A_CPU1_SB_CB<1>")
	)
	(segment
		(start 68.11899 -234.6452)
		(end 66.915538 -233.441748)
		(width 0.20066)
		(layer "F.Cu")
		(net "M_A_CPU1_SB_CB<1>")
	)
	(segment
		(start 66.320162 -233.441748)
		(end 66.176652 -233.441748)
		(width 0.101854)
		(layer "F.Cu")
		(net "M_A_CPU1_SB_CB<1>")
	)
	(segment
		(start 55.744364 -233.61142)
		(end 55.914036 -233.441748)
		(width 0.20066)
		(layer "F.Cu")
		(net "M_A_CPU1_SB_CB<1>")
	)
	(segment
		(start 62.827154 -233.86669)
		(end 60.947046 -233.86669)
		(width 0.20066)
		(layer "F.Cu")
		(net "M_A_CPU1_SB_CB<1>")
	)
	(segment
		(start 66.176652 -233.441748)
		(end 63.99403 -233.441748)
		(width 0.1016)
		(layer "F.Cu")
		(net "M_A_CPU1_SB_CB<1>")
	)
	(segment
		(start 63.252096 -233.441748)
		(end 62.827154 -233.86669)
		(width 0.20066)
		(layer "F.Cu")
		(net "M_A_CPU1_SB_CB<1>")
	)
	(segment
		(start 83.565492 -238.100616)
		(end 81.757266 -238.100616)
		(width 0.1016)
		(layer "F.Cu")
		(net "M_A_CPU1_SB_CB<1>")
	)
	(segment
		(start 60.073032 -233.916728)
		(end 60.12307 -233.86669)
		(width 0.20066)
		(layer "F.Cu")
		(net "M_A_CPU1_SB_CB<1>")
	)
	(segment
		(start 83.669378 -238.204502)
		(end 83.565492 -238.100616)
		(width 0.1016)
		(layer "F.Cu")
		(net "M_A_CPU1_SB_CB<1>")
	)
	(segment
		(start 53.403246 -233.86669)
		(end 54.960266 -233.86669)
		(width 0.20066)
		(layer "F.Cu")
		(net "M_A_CPU1_SB_CB<1>")
	)
	(segment
		(start 78.000098 -236.926628)
		(end 75.71867 -234.6452)
		(width 0.20066)
		(layer "F.Cu")
		(net "M_A_CPU1_SB_CB<1>")
	)
	(segment
		(start 58.768234 -233.441748)
		(end 58.895742 -233.441748)
		(width 0.20066)
		(layer "F.Cu")
		(net "M_A_CPU1_SB_CB<1>")
	)
	(segment
		(start 63.775336 -233.441748)
		(end 63.252096 -233.441748)
		(width 0.20066)
		(layer "F.Cu")
		(net "M_A_CPU1_SB_CB<1>")
	)
	(segment
		(start 84.207096 -238.204502)
		(end 83.669378 -238.204502)
		(width 0.1016)
		(layer "F.Cu")
		(net "M_A_CPU1_SB_CB<1>")
	)
	(segment
		(start 56.610758 -233.441748)
		(end 58.349134 -233.441748)
		(width 0.1016)
		(layer "F.Cu")
		(net "M_A_CPU1_SB_CB<1>")
	)
	(segment
		(start 55.914036 -233.441748)
		(end 56.245506 -233.441748)
		(width 0.20066)
		(layer "F.Cu")
		(net "M_A_CPU1_SB_CB<1>")
	)
	(segment
		(start 81.757266 -238.100616)
		(end 80.583278 -236.926628)
		(width 0.1016)
		(layer "F.Cu")
		(net "M_A_CPU1_SB_CB<1>")
	)
	(segment
		(start 85.795866 -238.761524)
		(end 86.106508 -238.761524)
		(width 0.088646)
		(layer "F.Cu")
		(net "M_A_CPU1_SB_CB<1>")
	)
	(segment
		(start 55.197248 -234.103672)
		(end 55.543704 -234.103672)
		(width 0.20066)
		(layer "F.Cu")
		(net "M_A_CPU1_SB_CB<1>")
	)
	(segment
		(start 80.583278 -236.926628)
		(end 80.387444 -236.926628)
		(width 0.1016)
		(layer "F.Cu")
		(net "M_A_CPU1_SB_CB<1>")
	)
	(segment
		(start 55.543704 -234.103672)
		(end 55.744364 -233.903012)
		(width 0.20066)
		(layer "F.Cu")
		(net "M_A_CPU1_SB_CB<1>")
	)
	(segment
		(start 80.387444 -236.926628)
		(end 78.000098 -236.926628)
		(width 0.20066)
		(layer "F.Cu")
		(net "M_A_CPU1_SB_CB<1>")
	)
	(segment
		(start 60.12307 -233.86669)
		(end 60.947046 -233.86669)
		(width 0.20066)
		(layer "F.Cu")
		(net "M_A_CPU1_SB_CB<1>")
	)
	(segment
		(start 66.915538 -233.441748)
		(end 66.320162 -233.441748)
		(width 0.20066)
		(layer "F.Cu")
		(net "M_A_CPU1_SB_CB<1>")
	)
	(segment
		(start 86.106508 -238.761524)
		(end 86.16569 -238.702342)
		(width 0.088646)
		(layer "F.Cu")
		(net "M_A_CPU1_SB_CB<1>")
	)
	(arc
		(start 85.608668 -238.436912)
		(mid 85.606034 -238.438372)
		(end 85.603334 -238.439706)
		(width 0.088646)
		(layer "F.Cu")
		(net "M_A_CPU1_SB_CB<1>")
	)
	(arc
		(start 85.795866 -238.386874)
		(mid 85.698965 -238.399554)
		(end 85.608668 -238.436912)
		(width 0.088646)
		(layer "F.Cu")
		(net "M_A_CPU1_SB_CB<1>")
	)
	(arc
		(start 85.603334 -238.439706)
		(mid 85.331965 -238.512595)
		(end 85.059012 -238.445802)
		(width 0.088646)
		(layer "F.Cu")
		(net "M_A_CPU1_SB_CB<1>")
	)
	(arc
		(start 85.059012 -238.445802)
		(mid 84.988855 -238.401541)
		(end 84.925916 -238.347504)
		(width 0.088646)
		(layer "F.Cu")
		(net "M_A_CPU1_SB_CB<1>")
	)
	(arc
		(start 85.991954 -238.442246)
		(mid 85.897744 -238.400984)
		(end 85.795866 -238.386874)
		(width 0.088646)
		(layer "F.Cu")
		(net "M_A_CPU1_SB_CB<1>")
	)
	(arc
		(start 86.16569 -238.702342)
		(mid 86.107311 -238.553246)
		(end 85.991954 -238.442246)
		(width 0.088646)
		(layer "F.Cu")
		(net "M_A_CPU1_SB_CB<1>")
	)
	(segment
		(start 80.555084 -238.249968)
		(end 77.408278 -238.249968)
		(width 0.20066)
		(layer "F.Cu")
		(net "M_A_CPU1_SB_CB<0>")
	)
	(segment
		(start 63.25235 -235.141516)
		(end 62.827154 -235.566712)
		(width 0.20066)
		(layer "F.Cu")
		(net "M_A_CPU1_SB_CB<0>")
	)
	(segment
		(start 81.504028 -238.710216)
		(end 81.04378 -238.249968)
		(width 0.1016)
		(layer "F.Cu")
		(net "M_A_CPU1_SB_CB<0>")
	)
	(segment
		(start 56.044338 -235.141516)
		(end 56.610758 -235.141516)
		(width 0.101854)
		(layer "F.Cu")
		(net "M_A_CPU1_SB_CB<0>")
	)
	(segment
		(start 55.583328 -235.342176)
		(end 55.783988 -235.141516)
		(width 0.20066)
		(layer "F.Cu")
		(net "M_A_CPU1_SB_CB<0>")
	)
	(segment
		(start 55.382668 -235.783374)
		(end 55.583328 -235.582714)
		(width 0.20066)
		(layer "F.Cu")
		(net "M_A_CPU1_SB_CB<0>")
	)
	(segment
		(start 56.610758 -235.141516)
		(end 58.349134 -235.141516)
		(width 0.1016)
		(layer "F.Cu")
		(net "M_A_CPU1_SB_CB<0>")
	)
	(segment
		(start 55.073296 -235.783374)
		(end 55.382668 -235.783374)
		(width 0.20066)
		(layer "F.Cu")
		(net "M_A_CPU1_SB_CB<0>")
	)
	(segment
		(start 68.745354 -236.604556)
		(end 68.28663 -236.145832)
		(width 0.20066)
		(layer "F.Cu")
		(net "M_A_CPU1_SB_CB<0>")
	)
	(segment
		(start 66.838576 -235.69803)
		(end 66.838576 -235.249212)
		(width 0.20066)
		(layer "F.Cu")
		(net "M_A_CPU1_SB_CB<0>")
	)
	(segment
		(start 63.578232 -235.141516)
		(end 63.25235 -235.141516)
		(width 0.20066)
		(layer "F.Cu")
		(net "M_A_CPU1_SB_CB<0>")
	)
	(segment
		(start 77.408278 -238.249968)
		(end 75.762866 -236.604556)
		(width 0.20066)
		(layer "F.Cu")
		(net "M_A_CPU1_SB_CB<0>")
	)
	(segment
		(start 58.98388 -235.141516)
		(end 59.0296 -235.141516)
		(width 0.20066)
		(layer "F.Cu")
		(net "M_A_CPU1_SB_CB<0>")
	)
	(segment
		(start 85.325712 -239.57534)
		(end 85.289644 -239.611408)
		(width 0.088646)
		(layer "F.Cu")
		(net "M_A_CPU1_SB_CB<0>")
	)
	(segment
		(start 83.191604 -238.710216)
		(end 81.504028 -238.710216)
		(width 0.1016)
		(layer "F.Cu")
		(net "M_A_CPU1_SB_CB<0>")
	)
	(segment
		(start 66.533776 -235.141516)
		(end 65.903348 -235.141516)
		(width 0.101854)
		(layer "F.Cu")
		(net "M_A_CPU1_SB_CB<0>")
	)
	(segment
		(start 54.808628 -235.518706)
		(end 55.073296 -235.783374)
		(width 0.20066)
		(layer "F.Cu")
		(net "M_A_CPU1_SB_CB<0>")
	)
	(segment
		(start 55.583328 -235.582714)
		(end 55.583328 -235.342176)
		(width 0.20066)
		(layer "F.Cu")
		(net "M_A_CPU1_SB_CB<0>")
	)
	(segment
		(start 81.04378 -238.249968)
		(end 80.555084 -238.249968)
		(width 0.1016)
		(layer "F.Cu")
		(net "M_A_CPU1_SB_CB<0>")
	)
	(segment
		(start 53.451252 -235.518706)
		(end 54.808628 -235.518706)
		(width 0.20066)
		(layer "F.Cu")
		(net "M_A_CPU1_SB_CB<0>")
	)
	(segment
		(start 55.783988 -235.141516)
		(end 56.044338 -235.141516)
		(width 0.20066)
		(layer "F.Cu")
		(net "M_A_CPU1_SB_CB<0>")
	)
	(segment
		(start 75.762866 -236.604556)
		(end 68.745354 -236.604556)
		(width 0.20066)
		(layer "F.Cu")
		(net "M_A_CPU1_SB_CB<0>")
	)
	(segment
		(start 53.403246 -235.566712)
		(end 53.451252 -235.518706)
		(width 0.20066)
		(layer "F.Cu")
		(net "M_A_CPU1_SB_CB<0>")
	)
	(segment
		(start 59.0296 -235.141516)
		(end 59.454796 -235.566712)
		(width 0.20066)
		(layer "F.Cu")
		(net "M_A_CPU1_SB_CB<0>")
	)
	(segment
		(start 66.73088 -235.141516)
		(end 66.533776 -235.141516)
		(width 0.20066)
		(layer "F.Cu")
		(net "M_A_CPU1_SB_CB<0>")
	)
	(segment
		(start 83.680046 -239.198658)
		(end 83.191604 -238.710216)
		(width 0.101854)
		(layer "F.Cu")
		(net "M_A_CPU1_SB_CB<0>")
	)
	(segment
		(start 59.454796 -235.566712)
		(end 60.947046 -235.566712)
		(width 0.20066)
		(layer "F.Cu")
		(net "M_A_CPU1_SB_CB<0>")
	)
	(segment
		(start 58.349134 -235.141516)
		(end 58.98388 -235.141516)
		(width 0.101854)
		(layer "F.Cu")
		(net "M_A_CPU1_SB_CB<0>")
	)
	(segment
		(start 68.28663 -236.145832)
		(end 67.286378 -236.145832)
		(width 0.20066)
		(layer "F.Cu")
		(net "M_A_CPU1_SB_CB<0>")
	)
	(segment
		(start 62.827154 -235.566712)
		(end 60.947046 -235.566712)
		(width 0.20066)
		(layer "F.Cu")
		(net "M_A_CPU1_SB_CB<0>")
	)
	(segment
		(start 67.286378 -236.145832)
		(end 66.838576 -235.69803)
		(width 0.20066)
		(layer "F.Cu")
		(net "M_A_CPU1_SB_CB<0>")
	)
	(segment
		(start 65.903348 -235.141516)
		(end 64.185292 -235.141516)
		(width 0.1016)
		(layer "F.Cu")
		(net "M_A_CPU1_SB_CB<0>")
	)
	(segment
		(start 84.092796 -239.611408)
		(end 83.680046 -239.198658)
		(width 0.088646)
		(layer "F.Cu")
		(net "M_A_CPU1_SB_CB<0>")
	)
	(segment
		(start 85.289644 -239.611408)
		(end 84.092796 -239.611408)
		(width 0.088646)
		(layer "F.Cu")
		(net "M_A_CPU1_SB_CB<0>")
	)
	(segment
		(start 64.185292 -235.141516)
		(end 63.578232 -235.141516)
		(width 0.101854)
		(layer "F.Cu")
		(net "M_A_CPU1_SB_CB<0>")
	)
	(segment
		(start 66.838576 -235.249212)
		(end 66.73088 -235.141516)
		(width 0.20066)
		(layer "F.Cu")
		(net "M_A_CPU1_SB_CB<0>")
	)
	(segment
		(start 59.533028 -247.466612)
		(end 60.947046 -247.466612)
		(width 0.20066)
		(layer "F.Cu")
		(net "M_A_CPU1_SB_CA<6>")
	)
	(segment
		(start 83.356196 -245.51894)
		(end 81.383124 -247.492012)
		(width 0.1016)
		(layer "F.Cu")
		(net "M_A_CPU1_SB_CA<6>")
	)
	(segment
		(start 58.704226 -247.891554)
		(end 59.108086 -247.891554)
		(width 0.20066)
		(layer "F.Cu")
		(net "M_A_CPU1_SB_CA<6>")
	)
	(segment
		(start 72.573134 -248.050812)
		(end 67.690746 -248.050812)
		(width 0.20066)
		(layer "F.Cu")
		(net "M_A_CPU1_SB_CA<6>")
	)
	(segment
		(start 67.690746 -248.050812)
		(end 67.547744 -247.90781)
		(width 0.20066)
		(layer "F.Cu")
		(net "M_A_CPU1_SB_CA<6>")
	)
	(segment
		(start 58.643012 -247.891554)
		(end 58.704226 -247.891554)
		(width 0.101854)
		(layer "F.Cu")
		(net "M_A_CPU1_SB_CA<6>")
	)
	(segment
		(start 63.749682 -247.899428)
		(end 63.316866 -247.466612)
		(width 0.20066)
		(layer "F.Cu")
		(net "M_A_CPU1_SB_CA<6>")
	)
	(segment
		(start 63.316866 -247.466612)
		(end 60.947046 -247.466612)
		(width 0.20066)
		(layer "F.Cu")
		(net "M_A_CPU1_SB_CA<6>")
	)
	(segment
		(start 63.985394 -247.899428)
		(end 63.977012 -247.899428)
		(width 0.101854)
		(layer "F.Cu")
		(net "M_A_CPU1_SB_CA<6>")
	)
	(segment
		(start 66.117724 -247.891554)
		(end 63.993268 -247.891554)
		(width 0.1016)
		(layer "F.Cu")
		(net "M_A_CPU1_SB_CA<6>")
	)
	(segment
		(start 56.445658 -247.904762)
		(end 56.458866 -247.891554)
		(width 0.101854)
		(layer "F.Cu")
		(net "M_A_CPU1_SB_CA<6>")
	)
	(segment
		(start 73.131934 -247.492012)
		(end 72.983598 -247.640348)
		(width 0.1016)
		(layer "F.Cu")
		(net "M_A_CPU1_SB_CA<6>")
	)
	(segment
		(start 55.769256 -248.35739)
		(end 56.221884 -247.904762)
		(width 0.20066)
		(layer "F.Cu")
		(net "M_A_CPU1_SB_CA<6>")
	)
	(segment
		(start 63.977012 -247.899428)
		(end 63.749682 -247.899428)
		(width 0.20066)
		(layer "F.Cu")
		(net "M_A_CPU1_SB_CA<6>")
	)
	(segment
		(start 56.221884 -247.904762)
		(end 56.37911 -247.904762)
		(width 0.20066)
		(layer "F.Cu")
		(net "M_A_CPU1_SB_CA<6>")
	)
	(segment
		(start 67.547744 -247.90781)
		(end 66.186812 -247.90781)
		(width 0.20066)
		(layer "F.Cu")
		(net "M_A_CPU1_SB_CA<6>")
	)
	(segment
		(start 54.319424 -247.466612)
		(end 55.210202 -248.35739)
		(width 0.20066)
		(layer "F.Cu")
		(net "M_A_CPU1_SB_CA<6>")
	)
	(segment
		(start 66.13398 -247.90781)
		(end 66.117724 -247.891554)
		(width 0.101854)
		(layer "F.Cu")
		(net "M_A_CPU1_SB_CA<6>")
	)
	(segment
		(start 72.983598 -247.640348)
		(end 72.573134 -248.050812)
		(width 0.20066)
		(layer "F.Cu")
		(net "M_A_CPU1_SB_CA<6>")
	)
	(segment
		(start 63.993268 -247.891554)
		(end 63.985394 -247.899428)
		(width 0.101854)
		(layer "F.Cu")
		(net "M_A_CPU1_SB_CA<6>")
	)
	(segment
		(start 84.609686 -245.51894)
		(end 84.130896 -245.51894)
		(width 0.088646)
		(layer "F.Cu")
		(net "M_A_CPU1_SB_CA<6>")
	)
	(segment
		(start 81.383124 -247.492012)
		(end 73.131934 -247.492012)
		(width 0.1016)
		(layer "F.Cu")
		(net "M_A_CPU1_SB_CA<6>")
	)
	(segment
		(start 84.856066 -245.27256)
		(end 84.609686 -245.51894)
		(width 0.088646)
		(layer "F.Cu")
		(net "M_A_CPU1_SB_CA<6>")
	)
	(segment
		(start 66.186812 -247.90781)
		(end 66.13398 -247.90781)
		(width 0.101854)
		(layer "F.Cu")
		(net "M_A_CPU1_SB_CA<6>")
	)
	(segment
		(start 59.108086 -247.891554)
		(end 59.533028 -247.466612)
		(width 0.20066)
		(layer "F.Cu")
		(net "M_A_CPU1_SB_CA<6>")
	)
	(segment
		(start 55.210202 -248.35739)
		(end 55.769256 -248.35739)
		(width 0.20066)
		(layer "F.Cu")
		(net "M_A_CPU1_SB_CA<6>")
	)
	(segment
		(start 84.130896 -245.51894)
		(end 83.356196 -245.51894)
		(width 0.1016)
		(layer "F.Cu")
		(net "M_A_CPU1_SB_CA<6>")
	)
	(segment
		(start 56.37911 -247.904762)
		(end 56.445658 -247.904762)
		(width 0.101854)
		(layer "F.Cu")
		(net "M_A_CPU1_SB_CA<6>")
	)
	(segment
		(start 56.458866 -247.891554)
		(end 58.643012 -247.891554)
		(width 0.1016)
		(layer "F.Cu")
		(net "M_A_CPU1_SB_CA<6>")
	)
	(segment
		(start 53.403246 -247.466612)
		(end 54.319424 -247.466612)
		(width 0.20066)
		(layer "F.Cu")
		(net "M_A_CPU1_SB_CA<6>")
	)
	(segment
		(start 59.62396 -248.758456)
		(end 59.822842 -248.758456)
		(width 0.20066)
		(layer "F.Cu")
		(net "M_A_CPU1_SB_CA<5>")
	)
	(segment
		(start 86.078568 -246.410988)
		(end 85.906356 -246.31142)
		(width 0.088646)
		(layer "F.Cu")
		(net "M_A_CPU1_SB_CA<5>")
	)
	(segment
		(start 59.822842 -248.758456)
		(end 59.896248 -248.758456)
		(width 0.101854)
		(layer "F.Cu")
		(net "M_A_CPU1_SB_CA<5>")
	)
	(segment
		(start 73.558908 -248.0056)
		(end 72.27697 -249.287538)
		(width 0.20066)
		(layer "F.Cu")
		(net "M_A_CPU1_SB_CA<5>")
	)
	(segment
		(start 64.219836 -248.31675)
		(end 65.047114 -248.31675)
		(width 0.20066)
		(layer "F.Cu")
		(net "M_A_CPU1_SB_CA<5>")
	)
	(segment
		(start 84.85124 -245.826534)
		(end 84.130896 -245.826534)
		(width 0.088646)
		(layer "F.Cu")
		(net "M_A_CPU1_SB_CA<5>")
	)
	(segment
		(start 84.130896 -245.826534)
		(end 83.479894 -245.826534)
		(width 0.1016)
		(layer "F.Cu")
		(net "M_A_CPU1_SB_CA<5>")
	)
	(segment
		(start 66.820542 -248.61647)
		(end 66.405252 -248.61647)
		(width 0.20066)
		(layer "F.Cu")
		(net "M_A_CPU1_SB_CA<5>")
	)
	(segment
		(start 62.620652 -248.396252)
		(end 62.767972 -248.248932)
		(width 0.20066)
		(layer "F.Cu")
		(net "M_A_CPU1_SB_CA<5>")
	)
	(segment
		(start 59.896248 -248.758456)
		(end 59.913012 -248.741692)
		(width 0.101854)
		(layer "F.Cu")
		(net "M_A_CPU1_SB_CA<5>")
	)
	(segment
		(start 59.913012 -248.741692)
		(end 62.072012 -248.741692)
		(width 0.1016)
		(layer "F.Cu")
		(net "M_A_CPU1_SB_CA<5>")
	)
	(segment
		(start 66.105532 -248.31675)
		(end 65.047114 -248.31675)
		(width 0.20066)
		(layer "F.Cu")
		(net "M_A_CPU1_SB_CA<5>")
	)
	(segment
		(start 72.27697 -249.287538)
		(end 67.49161 -249.287538)
		(width 0.20066)
		(layer "F.Cu")
		(net "M_A_CPU1_SB_CA<5>")
	)
	(segment
		(start 62.498732 -248.741692)
		(end 62.620652 -248.619772)
		(width 0.20066)
		(layer "F.Cu")
		(net "M_A_CPU1_SB_CA<5>")
	)
	(segment
		(start 63.331852 -248.528332)
		(end 64.008254 -248.528332)
		(width 0.20066)
		(layer "F.Cu")
		(net "M_A_CPU1_SB_CA<5>")
	)
	(segment
		(start 85.10524 -245.746524)
		(end 85.035644 -245.78437)
		(width 0.088646)
		(layer "F.Cu")
		(net "M_A_CPU1_SB_CA<5>")
	)
	(segment
		(start 63.052452 -248.248932)
		(end 63.331852 -248.528332)
		(width 0.20066)
		(layer "F.Cu")
		(net "M_A_CPU1_SB_CA<5>")
	)
	(segment
		(start 62.620652 -248.619772)
		(end 62.620652 -248.396252)
		(width 0.20066)
		(layer "F.Cu")
		(net "M_A_CPU1_SB_CA<5>")
	)
	(segment
		(start 85.588602 -245.761764)
		(end 85.558122 -245.744238)
		(width 0.088646)
		(layer "F.Cu")
		(net "M_A_CPU1_SB_CA<5>")
	)
	(segment
		(start 73.767696 -247.796812)
		(end 73.558908 -248.0056)
		(width 0.1016)
		(layer "F.Cu")
		(net "M_A_CPU1_SB_CA<5>")
	)
	(segment
		(start 62.072012 -248.741692)
		(end 62.147958 -248.741692)
		(width 0.101854)
		(layer "F.Cu")
		(net "M_A_CPU1_SB_CA<5>")
	)
	(segment
		(start 83.479894 -245.826534)
		(end 81.509616 -247.796812)
		(width 0.1016)
		(layer "F.Cu")
		(net "M_A_CPU1_SB_CA<5>")
	)
	(segment
		(start 64.008254 -248.528332)
		(end 64.219836 -248.31675)
		(width 0.20066)
		(layer "F.Cu")
		(net "M_A_CPU1_SB_CA<5>")
	)
	(segment
		(start 59.182 -248.316496)
		(end 59.62396 -248.758456)
		(width 0.20066)
		(layer "F.Cu")
		(net "M_A_CPU1_SB_CA<5>")
	)
	(segment
		(start 81.509616 -247.796812)
		(end 73.767696 -247.796812)
		(width 0.1016)
		(layer "F.Cu")
		(net "M_A_CPU1_SB_CA<5>")
	)
	(segment
		(start 59.181746 -248.31675)
		(end 59.182 -248.316496)
		(width 0.20066)
		(layer "F.Cu")
		(net "M_A_CPU1_SB_CA<5>")
	)
	(segment
		(start 67.49161 -249.287538)
		(end 66.820542 -248.61647)
		(width 0.20066)
		(layer "F.Cu")
		(net "M_A_CPU1_SB_CA<5>")
	)
	(segment
		(start 62.767972 -248.248932)
		(end 63.052452 -248.248932)
		(width 0.20066)
		(layer "F.Cu")
		(net "M_A_CPU1_SB_CA<5>")
	)
	(segment
		(start 87.205312 -246.08663)
		(end 86.828376 -246.463566)
		(width 0.088646)
		(layer "F.Cu")
		(net "M_A_CPU1_SB_CA<5>")
	)
	(segment
		(start 86.828376 -246.463566)
		(end 86.27491 -246.463566)
		(width 0.088646)
		(layer "F.Cu")
		(net "M_A_CPU1_SB_CA<5>")
	)
	(segment
		(start 84.854542 -245.829836)
		(end 84.85124 -245.826534)
		(width 0.088646)
		(layer "F.Cu")
		(net "M_A_CPU1_SB_CA<5>")
	)
	(segment
		(start 62.147958 -248.741692)
		(end 62.498732 -248.741692)
		(width 0.20066)
		(layer "F.Cu")
		(net "M_A_CPU1_SB_CA<5>")
	)
	(segment
		(start 57.503314 -248.31675)
		(end 59.181746 -248.31675)
		(width 0.20066)
		(layer "F.Cu")
		(net "M_A_CPU1_SB_CA<5>")
	)
	(segment
		(start 66.405252 -248.61647)
		(end 66.105532 -248.31675)
		(width 0.20066)
		(layer "F.Cu")
		(net "M_A_CPU1_SB_CA<5>")
	)
	(arc
		(start 85.558122 -245.744238)
		(mid 85.331364 -245.684447)
		(end 85.10524 -245.746524)
		(width 0.088646)
		(layer "F.Cu")
		(net "M_A_CPU1_SB_CA<5>")
	)
	(arc
		(start 85.906356 -246.31142)
		(mid 85.839268 -246.244309)
		(end 85.814662 -246.15267)
		(width 0.088646)
		(layer "F.Cu")
		(net "M_A_CPU1_SB_CA<5>")
	)
	(arc
		(start 85.814662 -246.15267)
		(mid 85.754086 -245.926876)
		(end 85.588602 -245.761764)
		(width 0.088646)
		(layer "F.Cu")
		(net "M_A_CPU1_SB_CA<5>")
	)
	(arc
		(start 86.27491 -246.463566)
		(mid 86.173279 -246.450195)
		(end 86.078568 -246.410988)
		(width 0.088646)
		(layer "F.Cu")
		(net "M_A_CPU1_SB_CA<5>")
	)
	(arc
		(start 85.035644 -245.78437)
		(mid 84.947905 -245.818308)
		(end 84.854542 -245.829836)
		(width 0.088646)
		(layer "F.Cu")
		(net "M_A_CPU1_SB_CA<5>")
	)
	(segment
		(start 65.888616 -249.591576)
		(end 64.119506 -249.591576)
		(width 0.1016)
		(layer "F.Cu")
		(net "M_A_CPU1_SB_CA<4>")
	)
	(segment
		(start 67.088258 -250.150122)
		(end 66.550032 -249.611896)
		(width 0.20066)
		(layer "F.Cu")
		(net "M_A_CPU1_SB_CA<4>")
	)
	(segment
		(start 66.186812 -249.611896)
		(end 66.166492 -249.591576)
		(width 0.101854)
		(layer "F.Cu")
		(net "M_A_CPU1_SB_CA<4>")
	)
	(segment
		(start 62.959488 -249.16638)
		(end 62.959234 -249.166634)
		(width 0.20066)
		(layer "F.Cu")
		(net "M_A_CPU1_SB_CA<4>")
	)
	(segment
		(start 59.107578 -249.591576)
		(end 59.53252 -249.166634)
		(width 0.20066)
		(layer "F.Cu")
		(net "M_A_CPU1_SB_CA<4>")
	)
	(segment
		(start 56.37911 -249.63628)
		(end 56.431942 -249.63628)
		(width 0.101854)
		(layer "F.Cu")
		(net "M_A_CPU1_SB_CA<4>")
	)
	(segment
		(start 85.325712 -246.08663)
		(end 84.905088 -246.170196)
		(width 0.088646)
		(layer "F.Cu")
		(net "M_A_CPU1_SB_CA<4>")
	)
	(segment
		(start 64.119506 -249.591576)
		(end 63.98641 -249.591576)
		(width 0.101854)
		(layer "F.Cu")
		(net "M_A_CPU1_SB_CA<4>")
	)
	(segment
		(start 83.876896 -246.170196)
		(end 83.567524 -246.170196)
		(width 0.1016)
		(layer "F.Cu")
		(net "M_A_CPU1_SB_CA<4>")
	)
	(segment
		(start 66.166492 -249.591576)
		(end 65.888616 -249.591576)
		(width 0.101854)
		(layer "F.Cu")
		(net "M_A_CPU1_SB_CA<4>")
	)
	(segment
		(start 58.643012 -249.591576)
		(end 58.704226 -249.591576)
		(width 0.101854)
		(layer "F.Cu")
		(net "M_A_CPU1_SB_CA<4>")
	)
	(segment
		(start 63.977012 -249.600974)
		(end 63.394082 -249.600974)
		(width 0.20066)
		(layer "F.Cu")
		(net "M_A_CPU1_SB_CA<4>")
	)
	(segment
		(start 84.905088 -246.170196)
		(end 83.876896 -246.170196)
		(width 0.088646)
		(layer "F.Cu")
		(net "M_A_CPU1_SB_CA<4>")
	)
	(segment
		(start 83.567524 -246.170196)
		(end 81.636108 -248.101612)
		(width 0.1016)
		(layer "F.Cu")
		(net "M_A_CPU1_SB_CA<4>")
	)
	(segment
		(start 81.636108 -248.101612)
		(end 74.36866 -248.101612)
		(width 0.1016)
		(layer "F.Cu")
		(net "M_A_CPU1_SB_CA<4>")
	)
	(segment
		(start 63.98641 -249.591576)
		(end 63.977012 -249.600974)
		(width 0.101854)
		(layer "F.Cu")
		(net "M_A_CPU1_SB_CA<4>")
	)
	(segment
		(start 72.32015 -250.150122)
		(end 67.088258 -250.150122)
		(width 0.20066)
		(layer "F.Cu")
		(net "M_A_CPU1_SB_CA<4>")
	)
	(segment
		(start 54.303422 -249.166634)
		(end 55.206392 -250.069604)
		(width 0.20066)
		(layer "F.Cu")
		(net "M_A_CPU1_SB_CA<4>")
	)
	(segment
		(start 59.53252 -249.166634)
		(end 60.947046 -249.166634)
		(width 0.20066)
		(layer "F.Cu")
		(net "M_A_CPU1_SB_CA<4>")
	)
	(segment
		(start 56.166004 -249.63628)
		(end 56.37911 -249.63628)
		(width 0.20066)
		(layer "F.Cu")
		(net "M_A_CPU1_SB_CA<4>")
	)
	(segment
		(start 56.476646 -249.591576)
		(end 58.643012 -249.591576)
		(width 0.1016)
		(layer "F.Cu")
		(net "M_A_CPU1_SB_CA<4>")
	)
	(segment
		(start 53.403246 -249.166634)
		(end 54.303422 -249.166634)
		(width 0.20066)
		(layer "F.Cu")
		(net "M_A_CPU1_SB_CA<4>")
	)
	(segment
		(start 62.959234 -249.166634)
		(end 60.947046 -249.166634)
		(width 0.20066)
		(layer "F.Cu")
		(net "M_A_CPU1_SB_CA<4>")
	)
	(segment
		(start 74.147934 -248.322338)
		(end 72.32015 -250.150122)
		(width 0.20066)
		(layer "F.Cu")
		(net "M_A_CPU1_SB_CA<4>")
	)
	(segment
		(start 74.36866 -248.101612)
		(end 74.147934 -248.322338)
		(width 0.1016)
		(layer "F.Cu")
		(net "M_A_CPU1_SB_CA<4>")
	)
	(segment
		(start 63.394082 -249.600974)
		(end 62.959488 -249.16638)
		(width 0.20066)
		(layer "F.Cu")
		(net "M_A_CPU1_SB_CA<4>")
	)
	(segment
		(start 66.550032 -249.611896)
		(end 66.186812 -249.611896)
		(width 0.20066)
		(layer "F.Cu")
		(net "M_A_CPU1_SB_CA<4>")
	)
	(segment
		(start 58.704226 -249.591576)
		(end 59.107578 -249.591576)
		(width 0.20066)
		(layer "F.Cu")
		(net "M_A_CPU1_SB_CA<4>")
	)
	(segment
		(start 56.431942 -249.63628)
		(end 56.476646 -249.591576)
		(width 0.101854)
		(layer "F.Cu")
		(net "M_A_CPU1_SB_CA<4>")
	)
	(segment
		(start 55.206392 -250.069604)
		(end 55.73268 -250.069604)
		(width 0.20066)
		(layer "F.Cu")
		(net "M_A_CPU1_SB_CA<4>")
	)
	(segment
		(start 55.73268 -250.069604)
		(end 56.166004 -249.63628)
		(width 0.20066)
		(layer "F.Cu")
		(net "M_A_CPU1_SB_CA<4>")
	)
	(segment
		(start 64.065404 -250.41606)
		(end 64.464692 -250.016772)
		(width 0.20066)
		(layer "F.Cu")
		(net "M_A_CPU1_SB_CA<3>")
	)
	(segment
		(start 57.503314 -250.016772)
		(end 58.731912 -250.016772)
		(width 0.20066)
		(layer "F.Cu")
		(net "M_A_CPU1_SB_CA<3>")
	)
	(segment
		(start 85.06841 -246.518176)
		(end 83.967828 -246.518176)
		(width 0.088646)
		(layer "F.Cu")
		(net "M_A_CPU1_SB_CA<3>")
	)
	(segment
		(start 83.967828 -246.518176)
		(end 83.908646 -246.577358)
		(width 0.088646)
		(layer "F.Cu")
		(net "M_A_CPU1_SB_CA<3>")
	)
	(segment
		(start 58.879232 -250.164092)
		(end 58.879232 -250.337828)
		(width 0.20066)
		(layer "F.Cu")
		(net "M_A_CPU1_SB_CA<3>")
	)
	(segment
		(start 64.464692 -250.016772)
		(end 65.047114 -250.016772)
		(width 0.20066)
		(layer "F.Cu")
		(net "M_A_CPU1_SB_CA<3>")
	)
	(segment
		(start 85.562186 -246.549164)
		(end 85.485224 -246.59336)
		(width 0.088646)
		(layer "F.Cu")
		(net "M_A_CPU1_SB_CA<3>")
	)
	(segment
		(start 62.790578 -250.08586)
		(end 63.332106 -250.08586)
		(width 0.20066)
		(layer "F.Cu")
		(net "M_A_CPU1_SB_CA<3>")
	)
	(segment
		(start 86.735666 -246.900446)
		(end 86.011004 -246.592344)
		(width 0.088646)
		(layer "F.Cu")
		(net "M_A_CPU1_SB_CA<3>")
	)
	(segment
		(start 74.698352 -248.720864)
		(end 72.243696 -251.17552)
		(width 0.20066)
		(layer "F.Cu")
		(net "M_A_CPU1_SB_CA<3>")
	)
	(segment
		(start 62.434724 -250.441714)
		(end 62.790578 -250.08586)
		(width 0.20066)
		(layer "F.Cu")
		(net "M_A_CPU1_SB_CA<3>")
	)
	(segment
		(start 58.879232 -250.337828)
		(end 59.002676 -250.461272)
		(width 0.20066)
		(layer "F.Cu")
		(net "M_A_CPU1_SB_CA<3>")
	)
	(segment
		(start 62.147958 -250.441714)
		(end 62.434724 -250.441714)
		(width 0.20066)
		(layer "F.Cu")
		(net "M_A_CPU1_SB_CA<3>")
	)
	(segment
		(start 66.037206 -250.016772)
		(end 65.047114 -250.016772)
		(width 0.20066)
		(layer "F.Cu")
		(net "M_A_CPU1_SB_CA<3>")
	)
	(segment
		(start 59.002676 -250.461272)
		(end 59.822842 -250.461272)
		(width 0.20066)
		(layer "F.Cu")
		(net "M_A_CPU1_SB_CA<3>")
	)
	(segment
		(start 67.132708 -250.91009)
		(end 66.787268 -250.766834)
		(width 0.20066)
		(layer "F.Cu")
		(net "M_A_CPU1_SB_CA<3>")
	)
	(segment
		(start 63.662306 -250.41606)
		(end 64.065404 -250.41606)
		(width 0.20066)
		(layer "F.Cu")
		(net "M_A_CPU1_SB_CA<3>")
	)
	(segment
		(start 67.77355 -251.17552)
		(end 67.132708 -250.91009)
		(width 0.20066)
		(layer "F.Cu")
		(net "M_A_CPU1_SB_CA<3>")
	)
	(segment
		(start 83.908646 -246.577358)
		(end 83.859878 -246.626126)
		(width 0.1016)
		(layer "F.Cu")
		(net "M_A_CPU1_SB_CA<3>")
	)
	(segment
		(start 58.731912 -250.016772)
		(end 58.879232 -250.164092)
		(width 0.20066)
		(layer "F.Cu")
		(net "M_A_CPU1_SB_CA<3>")
	)
	(segment
		(start 75.012804 -248.406412)
		(end 74.698352 -248.720864)
		(width 0.1016)
		(layer "F.Cu")
		(net "M_A_CPU1_SB_CA<3>")
	)
	(segment
		(start 83.542886 -246.626126)
		(end 81.7626 -248.406412)
		(width 0.1016)
		(layer "F.Cu")
		(net "M_A_CPU1_SB_CA<3>")
	)
	(segment
		(start 85.184488 -246.634254)
		(end 85.06841 -246.518176)
		(width 0.088646)
		(layer "F.Cu")
		(net "M_A_CPU1_SB_CA<3>")
	)
	(segment
		(start 81.7626 -248.406412)
		(end 75.012804 -248.406412)
		(width 0.1016)
		(layer "F.Cu")
		(net "M_A_CPU1_SB_CA<3>")
	)
	(segment
		(start 62.072012 -250.441714)
		(end 62.147958 -250.441714)
		(width 0.101854)
		(layer "F.Cu")
		(net "M_A_CPU1_SB_CA<3>")
	)
	(segment
		(start 72.243696 -251.17552)
		(end 67.77355 -251.17552)
		(width 0.20066)
		(layer "F.Cu")
		(net "M_A_CPU1_SB_CA<3>")
	)
	(segment
		(start 83.859878 -246.626126)
		(end 83.542886 -246.626126)
		(width 0.1016)
		(layer "F.Cu")
		(net "M_A_CPU1_SB_CA<3>")
	)
	(segment
		(start 59.868054 -250.461272)
		(end 59.887612 -250.441714)
		(width 0.101854)
		(layer "F.Cu")
		(net "M_A_CPU1_SB_CA<3>")
	)
	(segment
		(start 59.822842 -250.461272)
		(end 59.868054 -250.461272)
		(width 0.101854)
		(layer "F.Cu")
		(net "M_A_CPU1_SB_CA<3>")
	)
	(segment
		(start 66.787268 -250.766834)
		(end 66.037206 -250.016772)
		(width 0.20066)
		(layer "F.Cu")
		(net "M_A_CPU1_SB_CA<3>")
	)
	(segment
		(start 86.011004 -246.592344)
		(end 85.936328 -246.549164)
		(width 0.088646)
		(layer "F.Cu")
		(net "M_A_CPU1_SB_CA<3>")
	)
	(segment
		(start 63.332106 -250.08586)
		(end 63.662306 -250.41606)
		(width 0.20066)
		(layer "F.Cu")
		(net "M_A_CPU1_SB_CA<3>")
	)
	(segment
		(start 59.887612 -250.441714)
		(end 62.072012 -250.441714)
		(width 0.1016)
		(layer "F.Cu")
		(net "M_A_CPU1_SB_CA<3>")
	)
	(arc
		(start 85.485224 -246.59336)
		(mid 85.338866 -246.643225)
		(end 85.184488 -246.634254)
		(width 0.088646)
		(layer "F.Cu")
		(net "M_A_CPU1_SB_CA<3>")
	)
	(arc
		(start 85.936328 -246.549164)
		(mid 85.749274 -246.49908)
		(end 85.562186 -246.549164)
		(width 0.088646)
		(layer "F.Cu")
		(net "M_A_CPU1_SB_CA<3>")
	)
	(segment
		(start 84.622894 -247.5992)
		(end 84.1629 -247.5992)
		(width 0.088646)
		(layer "F.Cu")
		(net "M_A_CPU1_SB_CA<2>")
	)
	(segment
		(start 75.622404 -248.711212)
		(end 75.396852 -248.936764)
		(width 0.1016)
		(layer "F.Cu")
		(net "M_A_CPU1_SB_CA<2>")
	)
	(segment
		(start 72.416924 -251.916692)
		(end 67.015106 -251.916692)
		(width 0.20066)
		(layer "F.Cu")
		(net "M_A_CPU1_SB_CA<2>")
	)
	(segment
		(start 85.795866 -246.900446)
		(end 85.072474 -247.207786)
		(width 0.088646)
		(layer "F.Cu")
		(net "M_A_CPU1_SB_CA<2>")
	)
	(segment
		(start 55.17388 -251.766324)
		(end 55.526178 -251.766324)
		(width 0.20066)
		(layer "F.Cu")
		(net "M_A_CPU1_SB_CA<2>")
	)
	(segment
		(start 55.982108 -251.310394)
		(end 56.37911 -251.310394)
		(width 0.20066)
		(layer "F.Cu")
		(net "M_A_CPU1_SB_CA<2>")
	)
	(segment
		(start 63.441072 -251.313188)
		(end 62.99454 -250.866656)
		(width 0.20066)
		(layer "F.Cu")
		(net "M_A_CPU1_SB_CA<2>")
	)
	(segment
		(start 75.396852 -248.936764)
		(end 72.416924 -251.916692)
		(width 0.20066)
		(layer "F.Cu")
		(net "M_A_CPU1_SB_CA<2>")
	)
	(segment
		(start 58.704226 -251.291598)
		(end 59.108086 -251.291598)
		(width 0.20066)
		(layer "F.Cu")
		(net "M_A_CPU1_SB_CA<2>")
	)
	(segment
		(start 63.939166 -251.313188)
		(end 63.900812 -251.313188)
		(width 0.101854)
		(layer "F.Cu")
		(net "M_A_CPU1_SB_CA<2>")
	)
	(segment
		(start 83.937094 -247.825006)
		(end 83.050888 -248.711212)
		(width 0.1016)
		(layer "F.Cu")
		(net "M_A_CPU1_SB_CA<2>")
	)
	(segment
		(start 62.99454 -250.866656)
		(end 60.947046 -250.866656)
		(width 0.20066)
		(layer "F.Cu")
		(net "M_A_CPU1_SB_CA<2>")
	)
	(segment
		(start 63.960756 -251.291598)
		(end 63.939166 -251.313188)
		(width 0.101854)
		(layer "F.Cu")
		(net "M_A_CPU1_SB_CA<2>")
	)
	(segment
		(start 66.390012 -251.291598)
		(end 66.237612 -251.291598)
		(width 0.20066)
		(layer "F.Cu")
		(net "M_A_CPU1_SB_CA<2>")
	)
	(segment
		(start 85.072474 -247.207786)
		(end 84.933282 -247.288812)
		(width 0.088646)
		(layer "F.Cu")
		(net "M_A_CPU1_SB_CA<2>")
	)
	(segment
		(start 59.533028 -250.866656)
		(end 60.947046 -250.866656)
		(width 0.20066)
		(layer "F.Cu")
		(net "M_A_CPU1_SB_CA<2>")
	)
	(segment
		(start 56.433212 -251.291598)
		(end 58.668412 -251.291598)
		(width 0.1016)
		(layer "F.Cu")
		(net "M_A_CPU1_SB_CA<2>")
	)
	(segment
		(start 56.37911 -251.310394)
		(end 56.414416 -251.310394)
		(width 0.101854)
		(layer "F.Cu")
		(net "M_A_CPU1_SB_CA<2>")
	)
	(segment
		(start 63.900812 -251.313188)
		(end 63.441072 -251.313188)
		(width 0.20066)
		(layer "F.Cu")
		(net "M_A_CPU1_SB_CA<2>")
	)
	(segment
		(start 56.414416 -251.310394)
		(end 56.433212 -251.291598)
		(width 0.101854)
		(layer "F.Cu")
		(net "M_A_CPU1_SB_CA<2>")
	)
	(segment
		(start 59.108086 -251.291598)
		(end 59.533028 -250.866656)
		(width 0.20066)
		(layer "F.Cu")
		(net "M_A_CPU1_SB_CA<2>")
	)
	(segment
		(start 54.274212 -250.866656)
		(end 55.17388 -251.766324)
		(width 0.20066)
		(layer "F.Cu")
		(net "M_A_CPU1_SB_CA<2>")
	)
	(segment
		(start 67.015106 -251.916692)
		(end 66.390012 -251.291598)
		(width 0.20066)
		(layer "F.Cu")
		(net "M_A_CPU1_SB_CA<2>")
	)
	(segment
		(start 66.237612 -251.291598)
		(end 63.960756 -251.291598)
		(width 0.1016)
		(layer "F.Cu")
		(net "M_A_CPU1_SB_CA<2>")
	)
	(segment
		(start 84.1629 -247.5992)
		(end 83.937094 -247.825006)
		(width 0.088646)
		(layer "F.Cu")
		(net "M_A_CPU1_SB_CA<2>")
	)
	(segment
		(start 55.526178 -251.766324)
		(end 55.982108 -251.310394)
		(width 0.20066)
		(layer "F.Cu")
		(net "M_A_CPU1_SB_CA<2>")
	)
	(segment
		(start 58.668412 -251.291598)
		(end 58.704226 -251.291598)
		(width 0.101854)
		(layer "F.Cu")
		(net "M_A_CPU1_SB_CA<2>")
	)
	(segment
		(start 84.933282 -247.288812)
		(end 84.622894 -247.5992)
		(width 0.088646)
		(layer "F.Cu")
		(net "M_A_CPU1_SB_CA<2>")
	)
	(segment
		(start 83.050888 -248.711212)
		(end 75.622404 -248.711212)
		(width 0.1016)
		(layer "F.Cu")
		(net "M_A_CPU1_SB_CA<2>")
	)
	(segment
		(start 53.403246 -250.866656)
		(end 54.274212 -250.866656)
		(width 0.20066)
		(layer "F.Cu")
		(net "M_A_CPU1_SB_CA<2>")
	)
	(segment
		(start 59.187334 -251.716794)
		(end 59.631834 -252.161294)
		(width 0.20066)
		(layer "F.Cu")
		(net "M_A_CPU1_SB_CA<1>")
	)
	(segment
		(start 59.631834 -252.161294)
		(end 59.822842 -252.161294)
		(width 0.20066)
		(layer "F.Cu")
		(net "M_A_CPU1_SB_CA<1>")
	)
	(segment
		(start 63.476632 -251.962412)
		(end 63.973456 -251.962412)
		(width 0.20066)
		(layer "F.Cu")
		(net "M_A_CPU1_SB_CA<1>")
	)
	(segment
		(start 65.894966 -251.716794)
		(end 65.047114 -251.716794)
		(width 0.20066)
		(layer "F.Cu")
		(net "M_A_CPU1_SB_CA<1>")
	)
	(segment
		(start 87.205312 -248.46788)
		(end 86.885018 -248.147586)
		(width 0.088646)
		(layer "F.Cu")
		(net "M_A_CPU1_SB_CA<1>")
	)
	(segment
		(start 85.338412 -248.114312)
		(end 85.225636 -248.227088)
		(width 0.088646)
		(layer "F.Cu")
		(net "M_A_CPU1_SB_CA<1>")
	)
	(segment
		(start 76.274168 -249.016012)
		(end 76.065634 -249.224546)
		(width 0.1016)
		(layer "F.Cu")
		(net "M_A_CPU1_SB_CA<1>")
	)
	(segment
		(start 87.205312 -249.342148)
		(end 87.205312 -248.46788)
		(width 0.088646)
		(layer "F.Cu")
		(net "M_A_CPU1_SB_CA<1>")
	)
	(segment
		(start 62.633352 -251.80925)
		(end 62.813692 -251.62891)
		(width 0.20066)
		(layer "F.Cu")
		(net "M_A_CPU1_SB_CA<1>")
	)
	(segment
		(start 76.065634 -249.224546)
		(end 72.681846 -252.608334)
		(width 0.20066)
		(layer "F.Cu")
		(net "M_A_CPU1_SB_CA<1>")
	)
	(segment
		(start 84.85886 -249.016012)
		(end 83.75015 -249.016012)
		(width 0.088646)
		(layer "F.Cu")
		(net "M_A_CPU1_SB_CA<1>")
	)
	(segment
		(start 62.147958 -252.141736)
		(end 62.453012 -252.141736)
		(width 0.20066)
		(layer "F.Cu")
		(net "M_A_CPU1_SB_CA<1>")
	)
	(segment
		(start 85.225636 -248.227088)
		(end 85.225636 -248.649236)
		(width 0.088646)
		(layer "F.Cu")
		(net "M_A_CPU1_SB_CA<1>")
	)
	(segment
		(start 63.973456 -251.962412)
		(end 64.219074 -251.716794)
		(width 0.20066)
		(layer "F.Cu")
		(net "M_A_CPU1_SB_CA<1>")
	)
	(segment
		(start 62.097412 -252.141736)
		(end 62.147958 -252.141736)
		(width 0.101854)
		(layer "F.Cu")
		(net "M_A_CPU1_SB_CA<1>")
	)
	(segment
		(start 66.786506 -252.608334)
		(end 65.894966 -251.716794)
		(width 0.20066)
		(layer "F.Cu")
		(net "M_A_CPU1_SB_CA<1>")
	)
	(segment
		(start 72.681846 -252.608334)
		(end 66.786506 -252.608334)
		(width 0.20066)
		(layer "F.Cu")
		(net "M_A_CPU1_SB_CA<1>")
	)
	(segment
		(start 62.633352 -251.961396)
		(end 62.633352 -251.80925)
		(width 0.20066)
		(layer "F.Cu")
		(net "M_A_CPU1_SB_CA<1>")
	)
	(segment
		(start 85.225636 -248.649236)
		(end 84.85886 -249.016012)
		(width 0.088646)
		(layer "F.Cu")
		(net "M_A_CPU1_SB_CA<1>")
	)
	(segment
		(start 59.842654 -252.161294)
		(end 59.862212 -252.141736)
		(width 0.101854)
		(layer "F.Cu")
		(net "M_A_CPU1_SB_CA<1>")
	)
	(segment
		(start 86.078568 -248.03862)
		(end 86.068154 -248.032524)
		(width 0.088646)
		(layer "F.Cu")
		(net "M_A_CPU1_SB_CA<1>")
	)
	(segment
		(start 59.822842 -252.161294)
		(end 59.842654 -252.161294)
		(width 0.101854)
		(layer "F.Cu")
		(net "M_A_CPU1_SB_CA<1>")
	)
	(segment
		(start 62.453012 -252.141736)
		(end 62.633352 -251.961396)
		(width 0.20066)
		(layer "F.Cu")
		(net "M_A_CPU1_SB_CA<1>")
	)
	(segment
		(start 59.862212 -252.141736)
		(end 62.097412 -252.141736)
		(width 0.1016)
		(layer "F.Cu")
		(net "M_A_CPU1_SB_CA<1>")
	)
	(segment
		(start 63.14313 -251.62891)
		(end 63.476632 -251.962412)
		(width 0.20066)
		(layer "F.Cu")
		(net "M_A_CPU1_SB_CA<1>")
	)
	(segment
		(start 86.885018 -248.147586)
		(end 86.485476 -248.147586)
		(width 0.088646)
		(layer "F.Cu")
		(net "M_A_CPU1_SB_CA<1>")
	)
	(segment
		(start 64.219074 -251.716794)
		(end 65.047114 -251.716794)
		(width 0.20066)
		(layer "F.Cu")
		(net "M_A_CPU1_SB_CA<1>")
	)
	(segment
		(start 83.75015 -249.016012)
		(end 76.274168 -249.016012)
		(width 0.1016)
		(layer "F.Cu")
		(net "M_A_CPU1_SB_CA<1>")
	)
	(segment
		(start 62.813692 -251.62891)
		(end 63.14313 -251.62891)
		(width 0.20066)
		(layer "F.Cu")
		(net "M_A_CPU1_SB_CA<1>")
	)
	(segment
		(start 57.503314 -251.716794)
		(end 59.187334 -251.716794)
		(width 0.20066)
		(layer "F.Cu")
		(net "M_A_CPU1_SB_CA<1>")
	)
	(arc
		(start 86.485476 -248.147586)
		(mid 86.274861 -248.11986)
		(end 86.078568 -248.03862)
		(width 0.088646)
		(layer "F.Cu")
		(net "M_A_CPU1_SB_CA<1>")
	)
	(arc
		(start 86.068154 -248.032524)
		(mid 85.789722 -247.962678)
		(end 85.51291 -248.03862)
		(width 0.088646)
		(layer "F.Cu")
		(net "M_A_CPU1_SB_CA<1>")
	)
	(arc
		(start 85.51291 -248.03862)
		(mid 85.427823 -248.08145)
		(end 85.338412 -248.114312)
		(width 0.088646)
		(layer "F.Cu")
		(net "M_A_CPU1_SB_CA<1>")
	)
	(segment
		(start 58.643012 -252.141736)
		(end 58.704226 -252.141736)
		(width 0.101854)
		(layer "F.Cu")
		(net "M_A_CPU1_SB_CA<0>")
	)
	(segment
		(start 66.061336 -253.193296)
		(end 62.694312 -253.193296)
		(width 0.20066)
		(layer "F.Cu")
		(net "M_A_CPU1_SB_CA<0>")
	)
	(segment
		(start 66.4718 -253.60376)
		(end 66.061336 -253.193296)
		(width 0.20066)
		(layer "F.Cu")
		(net "M_A_CPU1_SB_CA<0>")
	)
	(segment
		(start 85.424518 -248.383806)
		(end 85.424518 -248.721118)
		(width 0.088646)
		(layer "F.Cu")
		(net "M_A_CPU1_SB_CA<0>")
	)
	(segment
		(start 76.583032 -249.614944)
		(end 72.594216 -253.60376)
		(width 0.20066)
		(layer "F.Cu")
		(net "M_A_CPU1_SB_CA<0>")
	)
	(segment
		(start 72.594216 -253.60376)
		(end 66.4718 -253.60376)
		(width 0.20066)
		(layer "F.Cu")
		(net "M_A_CPU1_SB_CA<0>")
	)
	(segment
		(start 59.229752 -252.566678)
		(end 60.947046 -252.566678)
		(width 0.20066)
		(layer "F.Cu")
		(net "M_A_CPU1_SB_CA<0>")
	)
	(segment
		(start 55.042308 -252.854968)
		(end 55.411116 -252.854968)
		(width 0.20066)
		(layer "F.Cu")
		(net "M_A_CPU1_SB_CA<0>")
	)
	(segment
		(start 56.40705 -252.115574)
		(end 56.433212 -252.141736)
		(width 0.101854)
		(layer "F.Cu")
		(net "M_A_CPU1_SB_CA<0>")
	)
	(segment
		(start 76.87691 -249.321066)
		(end 76.583032 -249.614944)
		(width 0.1016)
		(layer "F.Cu")
		(net "M_A_CPU1_SB_CA<0>")
	)
	(segment
		(start 55.722012 -252.544072)
		(end 55.722012 -252.319536)
		(width 0.20066)
		(layer "F.Cu")
		(net "M_A_CPU1_SB_CA<0>")
	)
	(segment
		(start 85.5472 -248.261124)
		(end 85.424518 -248.383806)
		(width 0.088646)
		(layer "F.Cu")
		(net "M_A_CPU1_SB_CA<0>")
	)
	(segment
		(start 58.80481 -252.141736)
		(end 59.229752 -252.566678)
		(width 0.20066)
		(layer "F.Cu")
		(net "M_A_CPU1_SB_CA<0>")
	)
	(segment
		(start 62.067694 -252.566678)
		(end 60.947046 -252.566678)
		(width 0.20066)
		(layer "F.Cu")
		(net "M_A_CPU1_SB_CA<0>")
	)
	(segment
		(start 83.90255 -249.321066)
		(end 76.87691 -249.321066)
		(width 0.1016)
		(layer "F.Cu")
		(net "M_A_CPU1_SB_CA<0>")
	)
	(segment
		(start 55.925974 -252.115574)
		(end 56.37911 -252.115574)
		(width 0.20066)
		(layer "F.Cu")
		(net "M_A_CPU1_SB_CA<0>")
	)
	(segment
		(start 56.433212 -252.141736)
		(end 58.643012 -252.141736)
		(width 0.1016)
		(layer "F.Cu")
		(net "M_A_CPU1_SB_CA<0>")
	)
	(segment
		(start 56.37911 -252.115574)
		(end 56.40705 -252.115574)
		(width 0.101854)
		(layer "F.Cu")
		(net "M_A_CPU1_SB_CA<0>")
	)
	(segment
		(start 62.694312 -253.193296)
		(end 62.067694 -252.566678)
		(width 0.20066)
		(layer "F.Cu")
		(net "M_A_CPU1_SB_CA<0>")
	)
	(segment
		(start 55.722012 -252.319536)
		(end 55.925974 -252.115574)
		(width 0.20066)
		(layer "F.Cu")
		(net "M_A_CPU1_SB_CA<0>")
	)
	(segment
		(start 86.380574 -248.433082)
		(end 85.98281 -248.20372)
		(width 0.088646)
		(layer "F.Cu")
		(net "M_A_CPU1_SB_CA<0>")
	)
	(segment
		(start 84.82457 -249.321066)
		(end 83.90255 -249.321066)
		(width 0.088646)
		(layer "F.Cu")
		(net "M_A_CPU1_SB_CA<0>")
	)
	(segment
		(start 54.754018 -252.566678)
		(end 55.042308 -252.854968)
		(width 0.20066)
		(layer "F.Cu")
		(net "M_A_CPU1_SB_CA<0>")
	)
	(segment
		(start 85.424518 -248.721118)
		(end 84.82457 -249.321066)
		(width 0.088646)
		(layer "F.Cu")
		(net "M_A_CPU1_SB_CA<0>")
	)
	(segment
		(start 53.403246 -252.566678)
		(end 54.754018 -252.566678)
		(width 0.20066)
		(layer "F.Cu")
		(net "M_A_CPU1_SB_CA<0>")
	)
	(segment
		(start 58.704226 -252.141736)
		(end 58.80481 -252.141736)
		(width 0.20066)
		(layer "F.Cu")
		(net "M_A_CPU1_SB_CA<0>")
	)
	(segment
		(start 55.411116 -252.854968)
		(end 55.722012 -252.544072)
		(width 0.20066)
		(layer "F.Cu")
		(net "M_A_CPU1_SB_CA<0>")
	)
	(arc
		(start 86.735666 -248.528078)
		(mid 86.55188 -248.503912)
		(end 86.380574 -248.433082)
		(width 0.088646)
		(layer "F.Cu")
		(net "M_A_CPU1_SB_CA<0>")
	)
	(arc
		(start 85.98281 -248.20372)
		(mid 85.75528 -248.158506)
		(end 85.5472 -248.261124)
		(width 0.088646)
		(layer "F.Cu")
		(net "M_A_CPU1_SB_CA<0>")
	)
	(segment
		(start 60.947046 -244.066568)
		(end 62.051946 -244.066568)
		(width 0.20066)
		(layer "F.Cu")
		(net "M_A_CPU1_SA_RSP<1>")
	)
	(segment
		(start 101.772466 -248.528078)
		(end 101.772466 -247.992392)
		(width 0.20066)
		(layer "F.Cu")
		(net "M_A_CPU1_SA_RSP<1>")
	)
	(segment
		(start 101.772466 -247.992392)
		(end 101.772212 -247.992138)
		(width 0.20066)
		(layer "F.Cu")
		(net "M_A_CPU1_SA_RSP<1>")
	)
	(segment
		(start 89.752678 -247.673876)
		(end 89.742264 -247.66778)
		(width 0.088646)
		(layer "In6.Cu")
		(net "M_A_CPU1_SA_RSP<1>")
	)
	(segment
		(start 66.193416 -245.069614)
		(end 63.054992 -245.069614)
		(width 0.18288)
		(layer "In6.Cu")
		(net "M_A_CPU1_SA_RSP<1>")
	)
	(segment
		(start 89.367868 -247.66778)
		(end 89.357454 -247.673876)
		(width 0.088646)
		(layer "In6.Cu")
		(net "M_A_CPU1_SA_RSP<1>")
	)
	(segment
		(start 91.247468 -247.66778)
		(end 91.237054 -247.673876)
		(width 0.088646)
		(layer "In6.Cu")
		(net "M_A_CPU1_SA_RSP<1>")
	)
	(segment
		(start 101.772212 -247.992138)
		(end 101.928676 -247.72112)
		(width 0.088646)
		(layer "In6.Cu")
		(net "M_A_CPU1_SA_RSP<1>")
	)
	(segment
		(start 72.53224 -248.331736)
		(end 69.455538 -248.331736)
		(width 0.18288)
		(layer "In6.Cu")
		(net "M_A_CPU1_SA_RSP<1>")
	)
	(segment
		(start 95.946468 -247.66778)
		(end 95.936054 -247.673876)
		(width 0.088646)
		(layer "In6.Cu")
		(net "M_A_CPU1_SA_RSP<1>")
	)
	(segment
		(start 94.066614 -247.66778)
		(end 94.051882 -247.676416)
		(width 0.088646)
		(layer "In6.Cu")
		(net "M_A_CPU1_SA_RSP<1>")
	)
	(segment
		(start 99.71151 -247.664224)
		(end 99.705414 -247.66778)
		(width 0.088646)
		(layer "In6.Cu")
		(net "M_A_CPU1_SA_RSP<1>")
	)
	(segment
		(start 63.054992 -245.069614)
		(end 62.051946 -244.066568)
		(width 0.18288)
		(layer "In6.Cu")
		(net "M_A_CPU1_SA_RSP<1>")
	)
	(segment
		(start 100.175568 -246.853964)
		(end 100.166678 -246.859044)
		(width 0.088646)
		(layer "In6.Cu")
		(net "M_A_CPU1_SA_RSP<1>")
	)
	(segment
		(start 91.632278 -247.673876)
		(end 91.621864 -247.66778)
		(width 0.088646)
		(layer "In6.Cu")
		(net "M_A_CPU1_SA_RSP<1>")
	)
	(segment
		(start 83.855814 -248.308368)
		(end 83.520534 -248.308368)
		(width 0.088646)
		(layer "In6.Cu")
		(net "M_A_CPU1_SA_RSP<1>")
	)
	(segment
		(start 99.705414 -247.66778)
		(end 99.690682 -247.676416)
		(width 0.088646)
		(layer "In6.Cu")
		(net "M_A_CPU1_SA_RSP<1>")
	)
	(segment
		(start 81.715356 -248.308368)
		(end 80.108806 -246.701818)
		(width 0.18288)
		(layer "In6.Cu")
		(net "M_A_CPU1_SA_RSP<1>")
	)
	(segment
		(start 101.928676 -247.72112)
		(end 101.904546 -247.631966)
		(width 0.088646)
		(layer "In6.Cu")
		(net "M_A_CPU1_SA_RSP<1>")
	)
	(segment
		(start 93.126814 -247.66778)
		(end 93.112082 -247.676416)
		(width 0.088646)
		(layer "In6.Cu")
		(net "M_A_CPU1_SA_RSP<1>")
	)
	(segment
		(start 98.210878 -247.673876)
		(end 98.200464 -247.66778)
		(width 0.088646)
		(layer "In6.Cu")
		(net "M_A_CPU1_SA_RSP<1>")
	)
	(segment
		(start 95.006414 -247.66778)
		(end 94.991682 -247.676416)
		(width 0.088646)
		(layer "In6.Cu")
		(net "M_A_CPU1_SA_RSP<1>")
	)
	(segment
		(start 84.118196 -248.199656)
		(end 83.855814 -248.308368)
		(width 0.088646)
		(layer "In6.Cu")
		(net "M_A_CPU1_SA_RSP<1>")
	)
	(segment
		(start 97.826068 -247.66778)
		(end 97.815654 -247.673876)
		(width 0.088646)
		(layer "In6.Cu")
		(net "M_A_CPU1_SA_RSP<1>")
	)
	(segment
		(start 101.498654 -246.859044)
		(end 101.489764 -246.853964)
		(width 0.088646)
		(layer "In6.Cu")
		(net "M_A_CPU1_SA_RSP<1>")
	)
	(segment
		(start 69.455538 -248.331736)
		(end 66.193416 -245.069614)
		(width 0.18288)
		(layer "In6.Cu")
		(net "M_A_CPU1_SA_RSP<1>")
	)
	(segment
		(start 83.520534 -248.308368)
		(end 81.715356 -248.308368)
		(width 0.18288)
		(layer "In6.Cu")
		(net "M_A_CPU1_SA_RSP<1>")
	)
	(segment
		(start 80.108806 -246.701818)
		(end 74.162158 -246.701818)
		(width 0.18288)
		(layer "In6.Cu")
		(net "M_A_CPU1_SA_RSP<1>")
	)
	(segment
		(start 84.59089 -247.726962)
		(end 84.118196 -248.199656)
		(width 0.088646)
		(layer "In6.Cu")
		(net "M_A_CPU1_SA_RSP<1>")
	)
	(segment
		(start 74.162158 -246.701818)
		(end 72.53224 -248.331736)
		(width 0.18288)
		(layer "In6.Cu")
		(net "M_A_CPU1_SA_RSP<1>")
	)
	(segment
		(start 88.427814 -247.66778)
		(end 88.4174 -247.673876)
		(width 0.088646)
		(layer "In6.Cu")
		(net "M_A_CPU1_SA_RSP<1>")
	)
	(segment
		(start 96.331278 -247.673876)
		(end 96.320864 -247.66778)
		(width 0.088646)
		(layer "In6.Cu")
		(net "M_A_CPU1_SA_RSP<1>")
	)
	(segment
		(start 101.677216 -247.193816)
		(end 101.677216 -247.178322)
		(width 0.088646)
		(layer "In6.Cu")
		(net "M_A_CPU1_SA_RSP<1>")
	)
	(arc
		(start 92.187014 -247.66778)
		(mid 91.910455 -247.743523)
		(end 91.632278 -247.673876)
		(width 0.088646)
		(layer "In6.Cu")
		(net "M_A_CPU1_SA_RSP<1>")
	)
	(arc
		(start 85.983064 -247.66778)
		(mid 85.795866 -247.617637)
		(end 85.608668 -247.66778)
		(width 0.088646)
		(layer "In6.Cu")
		(net "M_A_CPU1_SA_RSP<1>")
	)
	(arc
		(start 100.549964 -246.853964)
		(mid 100.362766 -246.803821)
		(end 100.175568 -246.853964)
		(width 0.088646)
		(layer "In6.Cu")
		(net "M_A_CPU1_SA_RSP<1>")
	)
	(arc
		(start 98.765614 -247.66778)
		(mid 98.489055 -247.743523)
		(end 98.210878 -247.673876)
		(width 0.088646)
		(layer "In6.Cu")
		(net "M_A_CPU1_SA_RSP<1>")
	)
	(arc
		(start 85.608668 -247.66778)
		(mid 85.325966 -247.743556)
		(end 85.043264 -247.66778)
		(width 0.088646)
		(layer "In6.Cu")
		(net "M_A_CPU1_SA_RSP<1>")
	)
	(arc
		(start 86.922864 -247.66778)
		(mid 86.735666 -247.617637)
		(end 86.548468 -247.66778)
		(width 0.088646)
		(layer "In6.Cu")
		(net "M_A_CPU1_SA_RSP<1>")
	)
	(arc
		(start 99.690682 -247.676416)
		(mid 99.414207 -247.743736)
		(end 99.14001 -247.66778)
		(width 0.088646)
		(layer "In6.Cu")
		(net "M_A_CPU1_SA_RSP<1>")
	)
	(arc
		(start 94.44101 -247.66778)
		(mid 94.253812 -247.617637)
		(end 94.066614 -247.66778)
		(width 0.088646)
		(layer "In6.Cu")
		(net "M_A_CPU1_SA_RSP<1>")
	)
	(arc
		(start 89.742264 -247.66778)
		(mid 89.555066 -247.617637)
		(end 89.367868 -247.66778)
		(width 0.088646)
		(layer "In6.Cu")
		(net "M_A_CPU1_SA_RSP<1>")
	)
	(arc
		(start 92.56141 -247.66778)
		(mid 92.374212 -247.617637)
		(end 92.187014 -247.66778)
		(width 0.088646)
		(layer "In6.Cu")
		(net "M_A_CPU1_SA_RSP<1>")
	)
	(arc
		(start 101.115368 -246.853964)
		(mid 100.832666 -246.92974)
		(end 100.549964 -246.853964)
		(width 0.088646)
		(layer "In6.Cu")
		(net "M_A_CPU1_SA_RSP<1>")
	)
	(arc
		(start 96.886014 -247.66778)
		(mid 96.609455 -247.743523)
		(end 96.331278 -247.673876)
		(width 0.088646)
		(layer "In6.Cu")
		(net "M_A_CPU1_SA_RSP<1>")
	)
	(arc
		(start 93.50121 -247.66778)
		(mid 93.314012 -247.617637)
		(end 93.126814 -247.66778)
		(width 0.088646)
		(layer "In6.Cu")
		(net "M_A_CPU1_SA_RSP<1>")
	)
	(arc
		(start 91.237054 -247.673876)
		(mid 90.958622 -247.743722)
		(end 90.68181 -247.66778)
		(width 0.088646)
		(layer "In6.Cu")
		(net "M_A_CPU1_SA_RSP<1>")
	)
	(arc
		(start 99.14001 -247.66778)
		(mid 98.952812 -247.617637)
		(end 98.765614 -247.66778)
		(width 0.088646)
		(layer "In6.Cu")
		(net "M_A_CPU1_SA_RSP<1>")
	)
	(arc
		(start 85.043264 -247.66778)
		(mid 84.856066 -247.617637)
		(end 84.668868 -247.66778)
		(width 0.088646)
		(layer "In6.Cu")
		(net "M_A_CPU1_SA_RSP<1>")
	)
	(arc
		(start 95.936054 -247.673876)
		(mid 95.657622 -247.743722)
		(end 95.38081 -247.66778)
		(width 0.088646)
		(layer "In6.Cu")
		(net "M_A_CPU1_SA_RSP<1>")
	)
	(arc
		(start 99.988116 -247.178322)
		(mid 99.914125 -247.457888)
		(end 99.71151 -247.664224)
		(width 0.088646)
		(layer "In6.Cu")
		(net "M_A_CPU1_SA_RSP<1>")
	)
	(arc
		(start 89.357454 -247.673876)
		(mid 89.079022 -247.743722)
		(end 88.80221 -247.66778)
		(width 0.088646)
		(layer "In6.Cu")
		(net "M_A_CPU1_SA_RSP<1>")
	)
	(arc
		(start 87.862664 -247.66778)
		(mid 87.675466 -247.617637)
		(end 87.488268 -247.66778)
		(width 0.088646)
		(layer "In6.Cu")
		(net "M_A_CPU1_SA_RSP<1>")
	)
	(arc
		(start 100.166678 -246.859044)
		(mid 100.035764 -246.995404)
		(end 99.988116 -247.178322)
		(width 0.088646)
		(layer "In6.Cu")
		(net "M_A_CPU1_SA_RSP<1>")
	)
	(arc
		(start 98.200464 -247.66778)
		(mid 98.013266 -247.617637)
		(end 97.826068 -247.66778)
		(width 0.088646)
		(layer "In6.Cu")
		(net "M_A_CPU1_SA_RSP<1>")
	)
	(arc
		(start 94.991682 -247.676416)
		(mid 94.715207 -247.743736)
		(end 94.44101 -247.66778)
		(width 0.088646)
		(layer "In6.Cu")
		(net "M_A_CPU1_SA_RSP<1>")
	)
	(arc
		(start 101.677216 -247.178322)
		(mid 101.629537 -246.995422)
		(end 101.498654 -246.859044)
		(width 0.088646)
		(layer "In6.Cu")
		(net "M_A_CPU1_SA_RSP<1>")
	)
	(arc
		(start 88.80221 -247.66778)
		(mid 88.615012 -247.617637)
		(end 88.427814 -247.66778)
		(width 0.088646)
		(layer "In6.Cu")
		(net "M_A_CPU1_SA_RSP<1>")
	)
	(arc
		(start 84.668868 -247.66778)
		(mid 84.627938 -247.694813)
		(end 84.59089 -247.726962)
		(width 0.088646)
		(layer "In6.Cu")
		(net "M_A_CPU1_SA_RSP<1>")
	)
	(arc
		(start 101.904546 -247.631966)
		(mid 101.740514 -247.439017)
		(end 101.677216 -247.193816)
		(width 0.088646)
		(layer "In6.Cu")
		(net "M_A_CPU1_SA_RSP<1>")
	)
	(arc
		(start 95.38081 -247.66778)
		(mid 95.193612 -247.617637)
		(end 95.006414 -247.66778)
		(width 0.088646)
		(layer "In6.Cu")
		(net "M_A_CPU1_SA_RSP<1>")
	)
	(arc
		(start 97.26041 -247.66778)
		(mid 97.073212 -247.617637)
		(end 96.886014 -247.66778)
		(width 0.088646)
		(layer "In6.Cu")
		(net "M_A_CPU1_SA_RSP<1>")
	)
	(arc
		(start 86.548468 -247.66778)
		(mid 86.265766 -247.743556)
		(end 85.983064 -247.66778)
		(width 0.088646)
		(layer "In6.Cu")
		(net "M_A_CPU1_SA_RSP<1>")
	)
	(arc
		(start 94.051882 -247.676416)
		(mid 93.775407 -247.743736)
		(end 93.50121 -247.66778)
		(width 0.088646)
		(layer "In6.Cu")
		(net "M_A_CPU1_SA_RSP<1>")
	)
	(arc
		(start 91.621864 -247.66778)
		(mid 91.434666 -247.617637)
		(end 91.247468 -247.66778)
		(width 0.088646)
		(layer "In6.Cu")
		(net "M_A_CPU1_SA_RSP<1>")
	)
	(arc
		(start 90.68181 -247.66778)
		(mid 90.494612 -247.617637)
		(end 90.307414 -247.66778)
		(width 0.088646)
		(layer "In6.Cu")
		(net "M_A_CPU1_SA_RSP<1>")
	)
	(arc
		(start 93.112082 -247.676416)
		(mid 92.835607 -247.743736)
		(end 92.56141 -247.66778)
		(width 0.088646)
		(layer "In6.Cu")
		(net "M_A_CPU1_SA_RSP<1>")
	)
	(arc
		(start 87.488268 -247.66778)
		(mid 87.205566 -247.743556)
		(end 86.922864 -247.66778)
		(width 0.088646)
		(layer "In6.Cu")
		(net "M_A_CPU1_SA_RSP<1>")
	)
	(arc
		(start 101.489764 -246.853964)
		(mid 101.302566 -246.803821)
		(end 101.115368 -246.853964)
		(width 0.088646)
		(layer "In6.Cu")
		(net "M_A_CPU1_SA_RSP<1>")
	)
	(arc
		(start 97.815654 -247.673876)
		(mid 97.537222 -247.743722)
		(end 97.26041 -247.66778)
		(width 0.088646)
		(layer "In6.Cu")
		(net "M_A_CPU1_SA_RSP<1>")
	)
	(arc
		(start 90.307414 -247.66778)
		(mid 90.030855 -247.743523)
		(end 89.752678 -247.673876)
		(width 0.088646)
		(layer "In6.Cu")
		(net "M_A_CPU1_SA_RSP<1>")
	)
	(arc
		(start 96.320864 -247.66778)
		(mid 96.133666 -247.617637)
		(end 95.946468 -247.66778)
		(width 0.088646)
		(layer "In6.Cu")
		(net "M_A_CPU1_SA_RSP<1>")
	)
	(arc
		(start 88.4174 -247.673876)
		(mid 88.139222 -247.743599)
		(end 87.862664 -247.66778)
		(width 0.088646)
		(layer "In6.Cu")
		(net "M_A_CPU1_SA_RSP<1>")
	)
	(segment
		(start 53.403246 -244.066568)
		(end 54.508146 -244.066568)
		(width 0.20066)
		(layer "F.Cu")
		(net "M_A_CPU1_SA_RSP<0>")
	)
	(segment
		(start 101.302312 -247.714262)
		(end 101.301296 -247.713246)
		(width 0.20066)
		(layer "F.Cu")
		(net "M_A_CPU1_SA_RSP<0>")
	)
	(segment
		(start 101.301296 -247.713246)
		(end 101.301296 -247.179592)
		(width 0.20066)
		(layer "F.Cu")
		(net "M_A_CPU1_SA_RSP<0>")
	)
	(segment
		(start 101.301296 -247.179592)
		(end 101.302566 -247.178322)
		(width 0.20066)
		(layer "F.Cu")
		(net "M_A_CPU1_SA_RSP<0>")
	)
	(segment
		(start 60.719208 -245.910862)
		(end 60.309252 -245.500906)
		(width 0.18288)
		(layer "In6.Cu")
		(net "M_A_CPU1_SA_RSP<0>")
	)
	(segment
		(start 100.54336 -247.710452)
		(end 100.444808 -247.809004)
		(width 0.088646)
		(layer "In6.Cu")
		(net "M_A_CPU1_SA_RSP<0>")
	)
	(segment
		(start 62.297818 -245.910862)
		(end 60.719208 -245.910862)
		(width 0.18288)
		(layer "In6.Cu")
		(net "M_A_CPU1_SA_RSP<0>")
	)
	(segment
		(start 83.520534 -249.297444)
		(end 82.221324 -249.297444)
		(width 0.18288)
		(layer "In6.Cu")
		(net "M_A_CPU1_SA_RSP<0>")
	)
	(segment
		(start 65.718944 -246.342154)
		(end 65.254632 -245.877842)
		(width 0.18288)
		(layer "In6.Cu")
		(net "M_A_CPU1_SA_RSP<0>")
	)
	(segment
		(start 54.87035 -243.985288)
		(end 54.589426 -243.985288)
		(width 0.18288)
		(layer "In6.Cu")
		(net "M_A_CPU1_SA_RSP<0>")
	)
	(segment
		(start 54.589426 -243.985288)
		(end 54.508146 -244.066568)
		(width 0.18288)
		(layer "In6.Cu")
		(net "M_A_CPU1_SA_RSP<0>")
	)
	(segment
		(start 74.528172 -247.039892)
		(end 72.565006 -249.003058)
		(width 0.18288)
		(layer "In6.Cu")
		(net "M_A_CPU1_SA_RSP<0>")
	)
	(segment
		(start 56.306974 -244.560598)
		(end 54.87035 -243.985288)
		(width 0.18288)
		(layer "In6.Cu")
		(net "M_A_CPU1_SA_RSP<0>")
	)
	(segment
		(start 60.309252 -245.500906)
		(end 60.309252 -244.698012)
		(width 0.18288)
		(layer "In6.Cu")
		(net "M_A_CPU1_SA_RSP<0>")
	)
	(segment
		(start 59.987688 -244.376448)
		(end 59.432444 -244.376448)
		(width 0.18288)
		(layer "In6.Cu")
		(net "M_A_CPU1_SA_RSP<0>")
	)
	(segment
		(start 69.217286 -249.003058)
		(end 66.556382 -246.342154)
		(width 0.18288)
		(layer "In6.Cu")
		(net "M_A_CPU1_SA_RSP<0>")
	)
	(segment
		(start 94.066614 -248.316496)
		(end 94.051882 -248.30786)
		(width 0.088646)
		(layer "In6.Cu")
		(net "M_A_CPU1_SA_RSP<0>")
	)
	(segment
		(start 86.640416 -248.787666)
		(end 86.640416 -248.806208)
		(width 0.088646)
		(layer "In6.Cu")
		(net "M_A_CPU1_SA_RSP<0>")
	)
	(segment
		(start 93.126814 -248.316496)
		(end 93.112082 -248.30786)
		(width 0.088646)
		(layer "In6.Cu")
		(net "M_A_CPU1_SA_RSP<0>")
	)
	(segment
		(start 98.765614 -248.316496)
		(end 98.7552 -248.3104)
		(width 0.088646)
		(layer "In6.Cu")
		(net "M_A_CPU1_SA_RSP<0>")
	)
	(segment
		(start 60.309252 -244.698012)
		(end 59.987688 -244.376448)
		(width 0.18288)
		(layer "In6.Cu")
		(net "M_A_CPU1_SA_RSP<0>")
	)
	(segment
		(start 96.886014 -248.316496)
		(end 96.8756 -248.3104)
		(width 0.088646)
		(layer "In6.Cu")
		(net "M_A_CPU1_SA_RSP<0>")
	)
	(segment
		(start 90.307414 -248.316496)
		(end 90.297 -248.3104)
		(width 0.088646)
		(layer "In6.Cu")
		(net "M_A_CPU1_SA_RSP<0>")
	)
	(segment
		(start 65.254632 -245.877842)
		(end 64.556894 -245.877842)
		(width 0.18288)
		(layer "In6.Cu")
		(net "M_A_CPU1_SA_RSP<0>")
	)
	(segment
		(start 66.556382 -246.342154)
		(end 65.718944 -246.342154)
		(width 0.18288)
		(layer "In6.Cu")
		(net "M_A_CPU1_SA_RSP<0>")
	)
	(segment
		(start 57.724548 -244.295422)
		(end 57.321704 -244.295422)
		(width 0.18288)
		(layer "In6.Cu")
		(net "M_A_CPU1_SA_RSP<0>")
	)
	(segment
		(start 92.187014 -248.316496)
		(end 92.1766 -248.3104)
		(width 0.088646)
		(layer "In6.Cu")
		(net "M_A_CPU1_SA_RSP<0>")
	)
	(segment
		(start 97.826068 -248.316496)
		(end 97.815654 -248.3104)
		(width 0.088646)
		(layer "In6.Cu")
		(net "M_A_CPU1_SA_RSP<0>")
	)
	(segment
		(start 101.302566 -247.178322)
		(end 100.611686 -247.65381)
		(width 0.088646)
		(layer "In6.Cu")
		(net "M_A_CPU1_SA_RSP<0>")
	)
	(segment
		(start 85.527896 -249.12193)
		(end 85.513164 -249.130566)
		(width 0.088646)
		(layer "In6.Cu")
		(net "M_A_CPU1_SA_RSP<0>")
	)
	(segment
		(start 62.927738 -246.540782)
		(end 62.297818 -245.910862)
		(width 0.18288)
		(layer "In6.Cu")
		(net "M_A_CPU1_SA_RSP<0>")
	)
	(segment
		(start 85.319108 -249.297444)
		(end 83.520534 -249.297444)
		(width 0.088646)
		(layer "In6.Cu")
		(net "M_A_CPU1_SA_RSP<0>")
	)
	(segment
		(start 85.39607 -249.220482)
		(end 85.319108 -249.297444)
		(width 0.088646)
		(layer "In6.Cu")
		(net "M_A_CPU1_SA_RSP<0>")
	)
	(segment
		(start 79.963772 -247.039892)
		(end 74.528172 -247.039892)
		(width 0.18288)
		(layer "In6.Cu")
		(net "M_A_CPU1_SA_RSP<0>")
	)
	(segment
		(start 59.432444 -244.376448)
		(end 59.248294 -244.560598)
		(width 0.18288)
		(layer "In6.Cu")
		(net "M_A_CPU1_SA_RSP<0>")
	)
	(segment
		(start 63.893954 -246.540782)
		(end 62.927738 -246.540782)
		(width 0.18288)
		(layer "In6.Cu")
		(net "M_A_CPU1_SA_RSP<0>")
	)
	(segment
		(start 64.556894 -245.877842)
		(end 63.893954 -246.540782)
		(width 0.18288)
		(layer "In6.Cu")
		(net "M_A_CPU1_SA_RSP<0>")
	)
	(segment
		(start 82.221324 -249.297444)
		(end 79.963772 -247.039892)
		(width 0.18288)
		(layer "In6.Cu")
		(net "M_A_CPU1_SA_RSP<0>")
	)
	(segment
		(start 86.461854 -249.125486)
		(end 86.452964 -249.130566)
		(width 0.088646)
		(layer "In6.Cu")
		(net "M_A_CPU1_SA_RSP<0>")
	)
	(segment
		(start 57.321704 -244.295422)
		(end 57.056528 -244.560598)
		(width 0.18288)
		(layer "In6.Cu")
		(net "M_A_CPU1_SA_RSP<0>")
	)
	(segment
		(start 95.946468 -248.316496)
		(end 95.936054 -248.3104)
		(width 0.088646)
		(layer "In6.Cu")
		(net "M_A_CPU1_SA_RSP<0>")
	)
	(segment
		(start 72.565006 -249.003058)
		(end 69.217286 -249.003058)
		(width 0.18288)
		(layer "In6.Cu")
		(net "M_A_CPU1_SA_RSP<0>")
	)
	(segment
		(start 99.705414 -248.316496)
		(end 99.690682 -248.30786)
		(width 0.088646)
		(layer "In6.Cu")
		(net "M_A_CPU1_SA_RSP<0>")
	)
	(segment
		(start 91.247468 -248.316496)
		(end 91.237054 -248.3104)
		(width 0.088646)
		(layer "In6.Cu")
		(net "M_A_CPU1_SA_RSP<0>")
	)
	(segment
		(start 88.427814 -248.316496)
		(end 88.4174 -248.3104)
		(width 0.088646)
		(layer "In6.Cu")
		(net "M_A_CPU1_SA_RSP<0>")
	)
	(segment
		(start 59.248294 -244.560598)
		(end 57.989724 -244.560598)
		(width 0.18288)
		(layer "In6.Cu")
		(net "M_A_CPU1_SA_RSP<0>")
	)
	(segment
		(start 89.367868 -248.316496)
		(end 89.357454 -248.3104)
		(width 0.088646)
		(layer "In6.Cu")
		(net "M_A_CPU1_SA_RSP<0>")
	)
	(segment
		(start 57.056528 -244.560598)
		(end 56.306974 -244.560598)
		(width 0.18288)
		(layer "In6.Cu")
		(net "M_A_CPU1_SA_RSP<0>")
	)
	(segment
		(start 57.989724 -244.560598)
		(end 57.724548 -244.295422)
		(width 0.18288)
		(layer "In6.Cu")
		(net "M_A_CPU1_SA_RSP<0>")
	)
	(arc
		(start 99.14001 -248.316496)
		(mid 98.952812 -248.366639)
		(end 98.765614 -248.316496)
		(width 0.088646)
		(layer "In6.Cu")
		(net "M_A_CPU1_SA_RSP<0>")
	)
	(arc
		(start 100.395786 -247.88241)
		(mid 100.283868 -248.132994)
		(end 100.07981 -248.316496)
		(width 0.088646)
		(layer "In6.Cu")
		(net "M_A_CPU1_SA_RSP<0>")
	)
	(arc
		(start 96.320864 -248.316496)
		(mid 96.133666 -248.366639)
		(end 95.946468 -248.316496)
		(width 0.088646)
		(layer "In6.Cu")
		(net "M_A_CPU1_SA_RSP<0>")
	)
	(arc
		(start 97.815654 -248.3104)
		(mid 97.537222 -248.240586)
		(end 97.26041 -248.316496)
		(width 0.088646)
		(layer "In6.Cu")
		(net "M_A_CPU1_SA_RSP<0>")
	)
	(arc
		(start 100.444808 -247.809004)
		(mid 100.416713 -247.843312)
		(end 100.395786 -247.88241)
		(width 0.088646)
		(layer "In6.Cu")
		(net "M_A_CPU1_SA_RSP<0>")
	)
	(arc
		(start 86.452964 -249.130566)
		(mid 86.265766 -249.180709)
		(end 86.078568 -249.130566)
		(width 0.088646)
		(layer "In6.Cu")
		(net "M_A_CPU1_SA_RSP<0>")
	)
	(arc
		(start 95.38081 -248.316496)
		(mid 95.193612 -248.366639)
		(end 95.006414 -248.316496)
		(width 0.088646)
		(layer "In6.Cu")
		(net "M_A_CPU1_SA_RSP<0>")
	)
	(arc
		(start 89.742264 -248.316496)
		(mid 89.555066 -248.366639)
		(end 89.367868 -248.316496)
		(width 0.088646)
		(layer "In6.Cu")
		(net "M_A_CPU1_SA_RSP<0>")
	)
	(arc
		(start 86.922864 -248.316496)
		(mid 86.720578 -248.515477)
		(end 86.640416 -248.787666)
		(width 0.088646)
		(layer "In6.Cu")
		(net "M_A_CPU1_SA_RSP<0>")
	)
	(arc
		(start 92.56141 -248.316496)
		(mid 92.374212 -248.366639)
		(end 92.187014 -248.316496)
		(width 0.088646)
		(layer "In6.Cu")
		(net "M_A_CPU1_SA_RSP<0>")
	)
	(arc
		(start 90.68181 -248.316496)
		(mid 90.494612 -248.366639)
		(end 90.307414 -248.316496)
		(width 0.088646)
		(layer "In6.Cu")
		(net "M_A_CPU1_SA_RSP<0>")
	)
	(arc
		(start 95.936054 -248.3104)
		(mid 95.657622 -248.240586)
		(end 95.38081 -248.316496)
		(width 0.088646)
		(layer "In6.Cu")
		(net "M_A_CPU1_SA_RSP<0>")
	)
	(arc
		(start 96.8756 -248.3104)
		(mid 96.597422 -248.240708)
		(end 96.320864 -248.316496)
		(width 0.088646)
		(layer "In6.Cu")
		(net "M_A_CPU1_SA_RSP<0>")
	)
	(arc
		(start 87.488268 -248.316496)
		(mid 87.205566 -248.240754)
		(end 86.922864 -248.316496)
		(width 0.088646)
		(layer "In6.Cu")
		(net "M_A_CPU1_SA_RSP<0>")
	)
	(arc
		(start 93.112082 -248.30786)
		(mid 92.835641 -248.240694)
		(end 92.56141 -248.316496)
		(width 0.088646)
		(layer "In6.Cu")
		(net "M_A_CPU1_SA_RSP<0>")
	)
	(arc
		(start 88.4174 -248.3104)
		(mid 88.139222 -248.240708)
		(end 87.862664 -248.316496)
		(width 0.088646)
		(layer "In6.Cu")
		(net "M_A_CPU1_SA_RSP<0>")
	)
	(arc
		(start 91.237054 -248.3104)
		(mid 90.958622 -248.240586)
		(end 90.68181 -248.316496)
		(width 0.088646)
		(layer "In6.Cu")
		(net "M_A_CPU1_SA_RSP<0>")
	)
	(arc
		(start 93.50121 -248.316496)
		(mid 93.314012 -248.366639)
		(end 93.126814 -248.316496)
		(width 0.088646)
		(layer "In6.Cu")
		(net "M_A_CPU1_SA_RSP<0>")
	)
	(arc
		(start 91.621864 -248.316496)
		(mid 91.434666 -248.366639)
		(end 91.247468 -248.316496)
		(width 0.088646)
		(layer "In6.Cu")
		(net "M_A_CPU1_SA_RSP<0>")
	)
	(arc
		(start 98.7552 -248.3104)
		(mid 98.477022 -248.240708)
		(end 98.200464 -248.316496)
		(width 0.088646)
		(layer "In6.Cu")
		(net "M_A_CPU1_SA_RSP<0>")
	)
	(arc
		(start 88.80221 -248.316496)
		(mid 88.615012 -248.366639)
		(end 88.427814 -248.316496)
		(width 0.088646)
		(layer "In6.Cu")
		(net "M_A_CPU1_SA_RSP<0>")
	)
	(arc
		(start 100.611686 -247.65381)
		(mid 100.57623 -247.680571)
		(end 100.54336 -247.710452)
		(width 0.088646)
		(layer "In6.Cu")
		(net "M_A_CPU1_SA_RSP<0>")
	)
	(arc
		(start 87.862664 -248.316496)
		(mid 87.675466 -248.366639)
		(end 87.488268 -248.316496)
		(width 0.088646)
		(layer "In6.Cu")
		(net "M_A_CPU1_SA_RSP<0>")
	)
	(arc
		(start 85.513164 -249.130566)
		(mid 85.451675 -249.171692)
		(end 85.39607 -249.220482)
		(width 0.088646)
		(layer "In6.Cu")
		(net "M_A_CPU1_SA_RSP<0>")
	)
	(arc
		(start 92.1766 -248.3104)
		(mid 91.898422 -248.240708)
		(end 91.621864 -248.316496)
		(width 0.088646)
		(layer "In6.Cu")
		(net "M_A_CPU1_SA_RSP<0>")
	)
	(arc
		(start 99.690682 -248.30786)
		(mid 99.414241 -248.240694)
		(end 99.14001 -248.316496)
		(width 0.088646)
		(layer "In6.Cu")
		(net "M_A_CPU1_SA_RSP<0>")
	)
	(arc
		(start 90.297 -248.3104)
		(mid 90.018822 -248.240708)
		(end 89.742264 -248.316496)
		(width 0.088646)
		(layer "In6.Cu")
		(net "M_A_CPU1_SA_RSP<0>")
	)
	(arc
		(start 89.357454 -248.3104)
		(mid 89.079022 -248.240586)
		(end 88.80221 -248.316496)
		(width 0.088646)
		(layer "In6.Cu")
		(net "M_A_CPU1_SA_RSP<0>")
	)
	(arc
		(start 86.640416 -248.806208)
		(mid 86.592737 -248.989108)
		(end 86.461854 -249.125486)
		(width 0.088646)
		(layer "In6.Cu")
		(net "M_A_CPU1_SA_RSP<0>")
	)
	(arc
		(start 95.006414 -248.316496)
		(mid 94.723712 -248.240754)
		(end 94.44101 -248.316496)
		(width 0.088646)
		(layer "In6.Cu")
		(net "M_A_CPU1_SA_RSP<0>")
	)
	(arc
		(start 97.26041 -248.316496)
		(mid 97.073212 -248.366639)
		(end 96.886014 -248.316496)
		(width 0.088646)
		(layer "In6.Cu")
		(net "M_A_CPU1_SA_RSP<0>")
	)
	(arc
		(start 94.44101 -248.316496)
		(mid 94.253812 -248.366639)
		(end 94.066614 -248.316496)
		(width 0.088646)
		(layer "In6.Cu")
		(net "M_A_CPU1_SA_RSP<0>")
	)
	(arc
		(start 86.078568 -249.130566)
		(mid 85.804369 -249.054731)
		(end 85.527896 -249.12193)
		(width 0.088646)
		(layer "In6.Cu")
		(net "M_A_CPU1_SA_RSP<0>")
	)
	(arc
		(start 94.051882 -248.30786)
		(mid 93.775441 -248.240694)
		(end 93.50121 -248.316496)
		(width 0.088646)
		(layer "In6.Cu")
		(net "M_A_CPU1_SA_RSP<0>")
	)
	(arc
		(start 98.200464 -248.316496)
		(mid 98.013266 -248.366639)
		(end 97.826068 -248.316496)
		(width 0.088646)
		(layer "In6.Cu")
		(net "M_A_CPU1_SA_RSP<0>")
	)
	(arc
		(start 100.07981 -248.316496)
		(mid 99.892612 -248.366639)
		(end 99.705414 -248.316496)
		(width 0.088646)
		(layer "In6.Cu")
		(net "M_A_CPU1_SA_RSP<0>")
	)
	(segment
		(start 84.536026 -253.649226)
		(end 83.173824 -255.011428)
		(width 0.088646)
		(layer "F.Cu")
		(net "M_A_CPU1_SA_PAR")
	)
	(segment
		(start 55.84825 -260.625082)
		(end 56.37911 -260.625082)
		(width 0.20066)
		(layer "F.Cu")
		(net "M_A_CPU1_SA_PAR")
	)
	(segment
		(start 65.93459 -260.641592)
		(end 64.029844 -260.641592)
		(width 0.1016)
		(layer "F.Cu")
		(net "M_A_CPU1_SA_PAR")
	)
	(segment
		(start 62.536832 -259.366766)
		(end 60.947046 -259.366766)
		(width 0.20066)
		(layer "F.Cu")
		(net "M_A_CPU1_SA_PAR")
	)
	(segment
		(start 66.977768 -260.209284)
		(end 66.615564 -260.359398)
		(width 0.20066)
		(layer "F.Cu")
		(net "M_A_CPU1_SA_PAR")
	)
	(segment
		(start 83.173824 -255.011428)
		(end 81.869026 -256.316226)
		(width 0.1016)
		(layer "F.Cu")
		(net "M_A_CPU1_SA_PAR")
	)
	(segment
		(start 58.617612 -260.641592)
		(end 58.704226 -260.641592)
		(width 0.101854)
		(layer "F.Cu")
		(net "M_A_CPU1_SA_PAR")
	)
	(segment
		(start 66.186812 -260.536944)
		(end 66.184018 -260.538214)
		(width 0.101854)
		(layer "F.Cu")
		(net "M_A_CPU1_SA_PAR")
	)
	(segment
		(start 56.37911 -260.625082)
		(end 56.416702 -260.625082)
		(width 0.101854)
		(layer "F.Cu")
		(net "M_A_CPU1_SA_PAR")
	)
	(segment
		(start 86.424262 -253.776226)
		(end 85.704426 -253.776226)
		(width 0.088646)
		(layer "F.Cu")
		(net "M_A_CPU1_SA_PAR")
	)
	(segment
		(start 58.704226 -260.641592)
		(end 58.78068 -260.641592)
		(width 0.20066)
		(layer "F.Cu")
		(net "M_A_CPU1_SA_PAR")
	)
	(segment
		(start 64.029844 -260.641592)
		(end 64.013334 -260.625082)
		(width 0.101854)
		(layer "F.Cu")
		(net "M_A_CPU1_SA_PAR")
	)
	(segment
		(start 86.845648 -254.197612)
		(end 86.424262 -253.776226)
		(width 0.088646)
		(layer "F.Cu")
		(net "M_A_CPU1_SA_PAR")
	)
	(segment
		(start 56.433212 -260.641592)
		(end 58.617612 -260.641592)
		(width 0.1016)
		(layer "F.Cu")
		(net "M_A_CPU1_SA_PAR")
	)
	(segment
		(start 54.589934 -259.366766)
		(end 55.84825 -260.625082)
		(width 0.20066)
		(layer "F.Cu")
		(net "M_A_CPU1_SA_PAR")
	)
	(segment
		(start 63.795148 -260.625082)
		(end 62.536832 -259.366766)
		(width 0.20066)
		(layer "F.Cu")
		(net "M_A_CPU1_SA_PAR")
	)
	(segment
		(start 74.19975 -256.237486)
		(end 73.94321 -256.237486)
		(width 0.20066)
		(layer "F.Cu")
		(net "M_A_CPU1_SA_PAR")
	)
	(segment
		(start 60.055506 -259.366766)
		(end 60.947046 -259.366766)
		(width 0.20066)
		(layer "F.Cu")
		(net "M_A_CPU1_SA_PAR")
	)
	(segment
		(start 73.94321 -256.237486)
		(end 68.832476 -258.354576)
		(width 0.20066)
		(layer "F.Cu")
		(net "M_A_CPU1_SA_PAR")
	)
	(segment
		(start 66.615564 -260.359398)
		(end 66.186812 -260.536944)
		(width 0.20066)
		(layer "F.Cu")
		(net "M_A_CPU1_SA_PAR")
	)
	(segment
		(start 53.403246 -259.366766)
		(end 54.589934 -259.366766)
		(width 0.20066)
		(layer "F.Cu")
		(net "M_A_CPU1_SA_PAR")
	)
	(segment
		(start 85.704426 -253.776226)
		(end 85.425026 -253.649226)
		(width 0.088646)
		(layer "F.Cu")
		(net "M_A_CPU1_SA_PAR")
	)
	(segment
		(start 64.013334 -260.625082)
		(end 63.977012 -260.625082)
		(width 0.101854)
		(layer "F.Cu")
		(net "M_A_CPU1_SA_PAR")
	)
	(segment
		(start 68.832476 -258.354576)
		(end 66.977768 -260.209284)
		(width 0.20066)
		(layer "F.Cu")
		(net "M_A_CPU1_SA_PAR")
	)
	(segment
		(start 56.416702 -260.625082)
		(end 56.433212 -260.641592)
		(width 0.101854)
		(layer "F.Cu")
		(net "M_A_CPU1_SA_PAR")
	)
	(segment
		(start 74.577956 -256.237486)
		(end 74.19975 -256.237486)
		(width 0.1016)
		(layer "F.Cu")
		(net "M_A_CPU1_SA_PAR")
	)
	(segment
		(start 63.977012 -260.625082)
		(end 63.795148 -260.625082)
		(width 0.20066)
		(layer "F.Cu")
		(net "M_A_CPU1_SA_PAR")
	)
	(segment
		(start 81.869026 -256.316226)
		(end 74.656696 -256.316226)
		(width 0.1016)
		(layer "F.Cu")
		(net "M_A_CPU1_SA_PAR")
	)
	(segment
		(start 58.78068 -260.641592)
		(end 60.055506 -259.366766)
		(width 0.20066)
		(layer "F.Cu")
		(net "M_A_CPU1_SA_PAR")
	)
	(segment
		(start 74.656696 -256.316226)
		(end 74.577956 -256.237486)
		(width 0.1016)
		(layer "F.Cu")
		(net "M_A_CPU1_SA_PAR")
	)
	(segment
		(start 66.184018 -260.538214)
		(end 65.93459 -260.641592)
		(width 0.1016)
		(layer "F.Cu")
		(net "M_A_CPU1_SA_PAR")
	)
	(segment
		(start 85.425026 -253.649226)
		(end 84.536026 -253.649226)
		(width 0.088646)
		(layer "F.Cu")
		(net "M_A_CPU1_SA_PAR")
	)
	(segment
		(start 82.129884 -262.006334)
		(end 83.064604 -262.006334)
		(width 0.1524)
		(layer "F.Cu")
		(net "M_A_CPU1_SA_DQS_DP<9>")
	)
	(segment
		(start 86.176866 -261.840218)
		(end 86.177374 -261.840726)
		(width 0.088646)
		(layer "F.Cu")
		(net "M_A_CPU1_SA_DQS_DP<9>")
	)
	(segment
		(start 65.327784 -273.816572)
		(end 65.328038 -273.816318)
		(width 0.20066)
		(layer "F.Cu")
		(net "M_A_CPU1_SA_DQS_DP<9>")
	)
	(segment
		(start 83.086702 -262.006334)
		(end 83.118452 -262.038084)
		(width 0.088646)
		(layer "F.Cu")
		(net "M_A_CPU1_SA_DQS_DP<9>")
	)
	(segment
		(start 58.885074 -273.655536)
		(end 59.17311 -273.655536)
		(width 0.20066)
		(layer "F.Cu")
		(net "M_A_CPU1_SA_DQS_DP<9>")
	)
	(segment
		(start 84.40547 -262.038084)
		(end 84.67217 -261.771384)
		(width 0.088646)
		(layer "F.Cu")
		(net "M_A_CPU1_SA_DQS_DP<9>")
	)
	(segment
		(start 66.753994 -274.321016)
		(end 66.878454 -274.196556)
		(width 0.20066)
		(layer "F.Cu")
		(net "M_A_CPU1_SA_DQS_DP<9>")
	)
	(segment
		(start 72.678036 -269.963646)
		(end 73.103994 -269.537688)
		(width 0.20066)
		(layer "F.Cu")
		(net "M_A_CPU1_SA_DQS_DP<9>")
	)
	(segment
		(start 75.318112 -267.551154)
		(end 76.585064 -267.551154)
		(width 0.1524)
		(layer "F.Cu")
		(net "M_A_CPU1_SA_DQS_DP<9>")
	)
	(segment
		(start 70.623176 -272.194274)
		(end 70.623176 -272.018506)
		(width 0.20066)
		(layer "F.Cu")
		(net "M_A_CPU1_SA_DQS_DP<9>")
	)
	(segment
		(start 83.992466 -261.949184)
		(end 84.192872 -261.949184)
		(width 0.088646)
		(layer "F.Cu")
		(net "M_A_CPU1_SA_DQS_DP<9>")
	)
	(segment
		(start 65.328038 -273.816318)
		(end 65.861692 -273.816318)
		(width 0.20066)
		(layer "F.Cu")
		(net "M_A_CPU1_SA_DQS_DP<9>")
	)
	(segment
		(start 63.301372 -273.652996)
		(end 63.937388 -274.077938)
		(width 0.20066)
		(layer "F.Cu")
		(net "M_A_CPU1_SA_DQS_DP<9>")
	)
	(segment
		(start 74.75982 -268.057884)
		(end 74.811128 -268.057884)
		(width 0.1524)
		(layer "F.Cu")
		(net "M_A_CPU1_SA_DQS_DP<9>")
	)
	(segment
		(start 67.604894 -274.321016)
		(end 68.206874 -274.321016)
		(width 0.20066)
		(layer "F.Cu")
		(net "M_A_CPU1_SA_DQS_DP<9>")
	)
	(segment
		(start 66.04381 -273.998436)
		(end 66.04381 -274.240498)
		(width 0.20066)
		(layer "F.Cu")
		(net "M_A_CPU1_SA_DQS_DP<9>")
	)
	(segment
		(start 66.878454 -274.196556)
		(end 67.480434 -274.196556)
		(width 0.20066)
		(layer "F.Cu")
		(net "M_A_CPU1_SA_DQS_DP<9>")
	)
	(segment
		(start 57.503314 -273.816572)
		(end 57.977786 -273.816572)
		(width 0.20066)
		(layer "F.Cu")
		(net "M_A_CPU1_SA_DQS_DP<9>")
	)
	(segment
		(start 66.124328 -274.321016)
		(end 66.753994 -274.321016)
		(width 0.20066)
		(layer "F.Cu")
		(net "M_A_CPU1_SA_DQS_DP<9>")
	)
	(segment
		(start 75.10907 -267.760196)
		(end 75.318112 -267.551154)
		(width 0.1524)
		(layer "F.Cu")
		(net "M_A_CPU1_SA_DQS_DP<9>")
	)
	(segment
		(start 71.225156 -271.592548)
		(end 71.650606 -271.167098)
		(width 0.20066)
		(layer "F.Cu")
		(net "M_A_CPU1_SA_DQS_DP<9>")
	)
	(segment
		(start 83.903566 -262.038084)
		(end 83.992466 -261.949184)
		(width 0.088646)
		(layer "F.Cu")
		(net "M_A_CPU1_SA_DQS_DP<9>")
	)
	(segment
		(start 76.585064 -267.551154)
		(end 82.129884 -262.006334)
		(width 0.1524)
		(layer "F.Cu")
		(net "M_A_CPU1_SA_DQS_DP<9>")
	)
	(segment
		(start 72.076564 -270.565118)
		(end 72.252586 -270.565118)
		(width 0.20066)
		(layer "F.Cu")
		(net "M_A_CPU1_SA_DQS_DP<9>")
	)
	(segment
		(start 68.206874 -274.321016)
		(end 69.327268 -273.490436)
		(width 0.20066)
		(layer "F.Cu")
		(net "M_A_CPU1_SA_DQS_DP<9>")
	)
	(segment
		(start 69.327268 -273.490436)
		(end 69.595746 -273.221958)
		(width 0.20066)
		(layer "F.Cu")
		(net "M_A_CPU1_SA_DQS_DP<9>")
	)
	(segment
		(start 73.280016 -269.537688)
		(end 73.705466 -269.112238)
		(width 0.20066)
		(layer "F.Cu")
		(net "M_A_CPU1_SA_DQS_DP<9>")
	)
	(segment
		(start 72.678036 -270.139668)
		(end 72.678036 -269.963646)
		(width 0.20066)
		(layer "F.Cu")
		(net "M_A_CPU1_SA_DQS_DP<9>")
	)
	(segment
		(start 86.177374 -261.840726)
		(end 86.538308 -262.021066)
		(width 0.088646)
		(layer "F.Cu")
		(net "M_A_CPU1_SA_DQS_DP<9>")
	)
	(segment
		(start 62.40653 -273.39163)
		(end 62.460886 -273.39163)
		(width 0.20066)
		(layer "F.Cu")
		(net "M_A_CPU1_SA_DQS_DP<9>")
	)
	(segment
		(start 83.413854 -261.949184)
		(end 83.61426 -261.949184)
		(width 0.088646)
		(layer "F.Cu")
		(net "M_A_CPU1_SA_DQS_DP<9>")
	)
	(segment
		(start 65.861692 -273.816318)
		(end 66.04381 -273.998436)
		(width 0.20066)
		(layer "F.Cu")
		(net "M_A_CPU1_SA_DQS_DP<9>")
	)
	(segment
		(start 62.722252 -273.652996)
		(end 63.301372 -273.652996)
		(width 0.20066)
		(layer "F.Cu")
		(net "M_A_CPU1_SA_DQS_DP<9>")
	)
	(segment
		(start 86.740746 -262.336534)
		(end 86.845648 -262.336534)
		(width 0.088646)
		(layer "F.Cu")
		(net "M_A_CPU1_SA_DQS_DP<9>")
	)
	(segment
		(start 65.047114 -273.816572)
		(end 65.327784 -273.816572)
		(width 0.20066)
		(layer "F.Cu")
		(net "M_A_CPU1_SA_DQS_DP<9>")
	)
	(segment
		(start 62.460886 -273.39163)
		(end 62.722252 -273.652996)
		(width 0.20066)
		(layer "F.Cu")
		(net "M_A_CPU1_SA_DQS_DP<9>")
	)
	(segment
		(start 83.61426 -261.949184)
		(end 83.70316 -262.038084)
		(width 0.088646)
		(layer "F.Cu")
		(net "M_A_CPU1_SA_DQS_DP<9>")
	)
	(segment
		(start 59.17311 -273.655536)
		(end 59.436762 -273.391884)
		(width 0.20066)
		(layer "F.Cu")
		(net "M_A_CPU1_SA_DQS_DP<9>")
	)
	(segment
		(start 71.650606 -270.991076)
		(end 72.076564 -270.565118)
		(width 0.20066)
		(layer "F.Cu")
		(net "M_A_CPU1_SA_DQS_DP<9>")
	)
	(segment
		(start 83.064604 -262.006334)
		(end 83.086702 -262.006334)
		(width 0.088646)
		(layer "F.Cu")
		(net "M_A_CPU1_SA_DQS_DP<9>")
	)
	(segment
		(start 73.705466 -269.112238)
		(end 73.705466 -268.936216)
		(width 0.20066)
		(layer "F.Cu")
		(net "M_A_CPU1_SA_DQS_DP<9>")
	)
	(segment
		(start 58.462672 -274.077938)
		(end 58.885074 -273.655536)
		(width 0.20066)
		(layer "F.Cu")
		(net "M_A_CPU1_SA_DQS_DP<9>")
	)
	(segment
		(start 74.811128 -268.057884)
		(end 75.10907 -267.760196)
		(width 0.1524)
		(layer "F.Cu")
		(net "M_A_CPU1_SA_DQS_DP<9>")
	)
	(segment
		(start 74.131424 -268.510258)
		(end 74.307446 -268.510258)
		(width 0.20066)
		(layer "F.Cu")
		(net "M_A_CPU1_SA_DQS_DP<9>")
	)
	(segment
		(start 64.557402 -273.816572)
		(end 65.047114 -273.816572)
		(width 0.20066)
		(layer "F.Cu")
		(net "M_A_CPU1_SA_DQS_DP<9>")
	)
	(segment
		(start 57.977786 -273.816572)
		(end 58.239152 -274.077938)
		(width 0.20066)
		(layer "F.Cu")
		(net "M_A_CPU1_SA_DQS_DP<9>")
	)
	(segment
		(start 60.06973 -273.39163)
		(end 62.40653 -273.39163)
		(width 0.1016)
		(layer "F.Cu")
		(net "M_A_CPU1_SA_DQS_DP<9>")
	)
	(segment
		(start 86.656418 -262.252206)
		(end 86.740746 -262.336534)
		(width 0.088646)
		(layer "F.Cu")
		(net "M_A_CPU1_SA_DQS_DP<9>")
	)
	(segment
		(start 70.021704 -272.619724)
		(end 70.197726 -272.619724)
		(width 0.20066)
		(layer "F.Cu")
		(net "M_A_CPU1_SA_DQS_DP<9>")
	)
	(segment
		(start 64.296036 -274.077938)
		(end 64.557402 -273.816572)
		(width 0.20066)
		(layer "F.Cu")
		(net "M_A_CPU1_SA_DQS_DP<9>")
	)
	(segment
		(start 63.937388 -274.077938)
		(end 64.296036 -274.077938)
		(width 0.20066)
		(layer "F.Cu")
		(net "M_A_CPU1_SA_DQS_DP<9>")
	)
	(segment
		(start 59.436762 -273.391884)
		(end 59.491118 -273.391884)
		(width 0.20066)
		(layer "F.Cu")
		(net "M_A_CPU1_SA_DQS_DP<9>")
	)
	(segment
		(start 84.192872 -261.949184)
		(end 84.281772 -262.038084)
		(width 0.088646)
		(layer "F.Cu")
		(net "M_A_CPU1_SA_DQS_DP<9>")
	)
	(segment
		(start 69.595746 -273.045682)
		(end 70.021704 -272.619724)
		(width 0.20066)
		(layer "F.Cu")
		(net "M_A_CPU1_SA_DQS_DP<9>")
	)
	(segment
		(start 73.705466 -268.936216)
		(end 74.131424 -268.510258)
		(width 0.20066)
		(layer "F.Cu")
		(net "M_A_CPU1_SA_DQS_DP<9>")
	)
	(segment
		(start 59.491118 -273.391884)
		(end 60.069476 -273.391884)
		(width 0.1016)
		(layer "F.Cu")
		(net "M_A_CPU1_SA_DQS_DP<9>")
	)
	(segment
		(start 72.252586 -270.565118)
		(end 72.678036 -270.139668)
		(width 0.20066)
		(layer "F.Cu")
		(net "M_A_CPU1_SA_DQS_DP<9>")
	)
	(segment
		(start 74.307446 -268.510258)
		(end 74.732896 -268.084808)
		(width 0.20066)
		(layer "F.Cu")
		(net "M_A_CPU1_SA_DQS_DP<9>")
	)
	(segment
		(start 66.04381 -274.240498)
		(end 66.124328 -274.321016)
		(width 0.20066)
		(layer "F.Cu")
		(net "M_A_CPU1_SA_DQS_DP<9>")
	)
	(segment
		(start 84.67217 -261.771384)
		(end 84.966048 -261.771384)
		(width 0.088646)
		(layer "F.Cu")
		(net "M_A_CPU1_SA_DQS_DP<9>")
	)
	(segment
		(start 83.118452 -262.038084)
		(end 83.324954 -262.038084)
		(width 0.088646)
		(layer "F.Cu")
		(net "M_A_CPU1_SA_DQS_DP<9>")
	)
	(segment
		(start 71.049134 -271.592548)
		(end 71.225156 -271.592548)
		(width 0.20066)
		(layer "F.Cu")
		(net "M_A_CPU1_SA_DQS_DP<9>")
	)
	(segment
		(start 70.197726 -272.619724)
		(end 70.623176 -272.194274)
		(width 0.20066)
		(layer "F.Cu")
		(net "M_A_CPU1_SA_DQS_DP<9>")
	)
	(segment
		(start 71.650606 -271.167098)
		(end 71.650606 -270.991076)
		(width 0.20066)
		(layer "F.Cu")
		(net "M_A_CPU1_SA_DQS_DP<9>")
	)
	(segment
		(start 74.732896 -268.084808)
		(end 74.75982 -268.057884)
		(width 0.1524)
		(layer "F.Cu")
		(net "M_A_CPU1_SA_DQS_DP<9>")
	)
	(segment
		(start 83.324954 -262.038084)
		(end 83.413854 -261.949184)
		(width 0.088646)
		(layer "F.Cu")
		(net "M_A_CPU1_SA_DQS_DP<9>")
	)
	(segment
		(start 84.281772 -262.038084)
		(end 84.40547 -262.038084)
		(width 0.088646)
		(layer "F.Cu")
		(net "M_A_CPU1_SA_DQS_DP<9>")
	)
	(segment
		(start 69.595746 -273.221958)
		(end 69.595746 -273.045682)
		(width 0.20066)
		(layer "F.Cu")
		(net "M_A_CPU1_SA_DQS_DP<9>")
	)
	(segment
		(start 70.623176 -272.018506)
		(end 71.049134 -271.592548)
		(width 0.20066)
		(layer "F.Cu")
		(net "M_A_CPU1_SA_DQS_DP<9>")
	)
	(segment
		(start 73.103994 -269.537688)
		(end 73.280016 -269.537688)
		(width 0.20066)
		(layer "F.Cu")
		(net "M_A_CPU1_SA_DQS_DP<9>")
	)
	(segment
		(start 58.239152 -274.077938)
		(end 58.462672 -274.077938)
		(width 0.20066)
		(layer "F.Cu")
		(net "M_A_CPU1_SA_DQS_DP<9>")
	)
	(segment
		(start 83.70316 -262.038084)
		(end 83.903566 -262.038084)
		(width 0.088646)
		(layer "F.Cu")
		(net "M_A_CPU1_SA_DQS_DP<9>")
	)
	(segment
		(start 67.480434 -274.196556)
		(end 67.604894 -274.321016)
		(width 0.20066)
		(layer "F.Cu")
		(net "M_A_CPU1_SA_DQS_DP<9>")
	)
	(segment
		(start 86.538308 -262.021066)
		(end 86.656418 -262.252206)
		(width 0.088646)
		(layer "F.Cu")
		(net "M_A_CPU1_SA_DQS_DP<9>")
	)
	(segment
		(start 60.069476 -273.391884)
		(end 60.06973 -273.39163)
		(width 0.1016)
		(layer "F.Cu")
		(net "M_A_CPU1_SA_DQS_DP<9>")
	)
	(arc
		(start 84.966048 -261.771384)
		(mid 85.112256 -261.790633)
		(end 85.248496 -261.847076)
		(width 0.088646)
		(layer "F.Cu")
		(net "M_A_CPU1_SA_DQS_DP<9>")
	)
	(arc
		(start 85.248496 -261.847076)
		(mid 85.435694 -261.897219)
		(end 85.622892 -261.847076)
		(width 0.088646)
		(layer "F.Cu")
		(net "M_A_CPU1_SA_DQS_DP<9>")
	)
	(arc
		(start 85.622892 -261.847076)
		(mid 85.898996 -261.77109)
		(end 86.176866 -261.840218)
		(width 0.088646)
		(layer "F.Cu")
		(net "M_A_CPU1_SA_DQS_DP<9>")
	)
	(segment
		(start 85.292184 -266.771628)
		(end 85.209126 -266.68857)
		(width 0.088646)
		(layer "F.Cu")
		(net "M_A_CPU1_SA_DQS_DP<8>")
	)
	(segment
		(start 58.21299 -283.40177)
		(end 58.475626 -283.40177)
		(width 0.20066)
		(layer "F.Cu")
		(net "M_A_CPU1_SA_DQS_DP<8>")
	)
	(segment
		(start 83.568794 -267.558774)
		(end 83.443064 -267.684504)
		(width 0.088646)
		(layer "F.Cu")
		(net "M_A_CPU1_SA_DQS_DP<8>")
	)
	(segment
		(start 83.840828 -267.433298)
		(end 83.715352 -267.558774)
		(width 0.088646)
		(layer "F.Cu")
		(net "M_A_CPU1_SA_DQS_DP<8>")
	)
	(segment
		(start 68.099178 -283.564584)
		(end 67.974718 -283.689044)
		(width 0.20066)
		(layer "F.Cu")
		(net "M_A_CPU1_SA_DQS_DP<8>")
	)
	(segment
		(start 73.836022 -281.297126)
		(end 73.66 -281.297126)
		(width 0.20066)
		(layer "F.Cu")
		(net "M_A_CPU1_SA_DQS_DP<8>")
	)
	(segment
		(start 67.372738 -283.689044)
		(end 67.248278 -283.564584)
		(width 0.20066)
		(layer "F.Cu")
		(net "M_A_CPU1_SA_DQS_DP<8>")
	)
	(segment
		(start 59.839352 -282.741878)
		(end 62.130686 -282.741878)
		(width 0.1016)
		(layer "F.Cu")
		(net "M_A_CPU1_SA_DQS_DP<8>")
	)
	(segment
		(start 84.113116 -267.16101)
		(end 83.966558 -267.16101)
		(width 0.088646)
		(layer "F.Cu")
		(net "M_A_CPU1_SA_DQS_DP<8>")
	)
	(segment
		(start 83.966558 -267.16101)
		(end 83.840828 -267.28674)
		(width 0.088646)
		(layer "F.Cu")
		(net "M_A_CPU1_SA_DQS_DP<8>")
	)
	(segment
		(start 72.808592 -282.324556)
		(end 72.63257 -282.324556)
		(width 0.20066)
		(layer "F.Cu")
		(net "M_A_CPU1_SA_DQS_DP<8>")
	)
	(segment
		(start 62.727332 -283.00299)
		(end 63.301372 -283.00299)
		(width 0.20066)
		(layer "F.Cu")
		(net "M_A_CPU1_SA_DQS_DP<8>")
	)
	(segment
		(start 62.455298 -282.730956)
		(end 62.727332 -283.00299)
		(width 0.20066)
		(layer "F.Cu")
		(net "M_A_CPU1_SA_DQS_DP<8>")
	)
	(segment
		(start 59.613038 -282.73121)
		(end 59.822842 -282.73121)
		(width 0.20066)
		(layer "F.Cu")
		(net "M_A_CPU1_SA_DQS_DP<8>")
	)
	(segment
		(start 70.78853 -283.644848)
		(end 70.566788 -283.689044)
		(width 0.20066)
		(layer "F.Cu")
		(net "M_A_CPU1_SA_DQS_DP<8>")
	)
	(segment
		(start 66.646298 -283.564584)
		(end 66.521838 -283.689044)
		(width 0.20066)
		(layer "F.Cu")
		(net "M_A_CPU1_SA_DQS_DP<8>")
	)
	(segment
		(start 75.760834 -276.62505)
		(end 75.077066 -279.879806)
		(width 0.1524)
		(layer "F.Cu")
		(net "M_A_CPU1_SA_DQS_DP<8>")
	)
	(segment
		(start 63.301372 -283.00299)
		(end 63.937388 -283.427932)
		(width 0.20066)
		(layer "F.Cu")
		(net "M_A_CPU1_SA_DQS_DP<8>")
	)
	(segment
		(start 67.248278 -283.564584)
		(end 66.646298 -283.564584)
		(width 0.20066)
		(layer "F.Cu")
		(net "M_A_CPU1_SA_DQS_DP<8>")
	)
	(segment
		(start 72.63257 -282.324556)
		(end 72.206612 -282.750514)
		(width 0.20066)
		(layer "F.Cu")
		(net "M_A_CPU1_SA_DQS_DP<8>")
	)
	(segment
		(start 66.038222 -283.573982)
		(end 66.038222 -283.342842)
		(width 0.20066)
		(layer "F.Cu")
		(net "M_A_CPU1_SA_DQS_DP<8>")
	)
	(segment
		(start 85.572854 -266.771628)
		(end 85.292184 -266.771628)
		(width 0.088646)
		(layer "F.Cu")
		(net "M_A_CPU1_SA_DQS_DP<8>")
	)
	(segment
		(start 68.701158 -283.564584)
		(end 68.099178 -283.564584)
		(width 0.20066)
		(layer "F.Cu")
		(net "M_A_CPU1_SA_DQS_DP<8>")
	)
	(segment
		(start 62.130686 -282.741878)
		(end 62.141608 -282.730956)
		(width 0.1016)
		(layer "F.Cu")
		(net "M_A_CPU1_SA_DQS_DP<8>")
	)
	(segment
		(start 58.475626 -283.40177)
		(end 58.871866 -283.00553)
		(width 0.20066)
		(layer "F.Cu")
		(net "M_A_CPU1_SA_DQS_DP<8>")
	)
	(segment
		(start 70.566788 -283.689044)
		(end 70.278498 -283.689044)
		(width 0.20066)
		(layer "F.Cu")
		(net "M_A_CPU1_SA_DQS_DP<8>")
	)
	(segment
		(start 74.339704 -280.844752)
		(end 74.288396 -280.844752)
		(width 0.1524)
		(layer "F.Cu")
		(net "M_A_CPU1_SA_DQS_DP<8>")
	)
	(segment
		(start 64.557402 -283.166566)
		(end 65.047114 -283.166566)
		(width 0.20066)
		(layer "F.Cu")
		(net "M_A_CPU1_SA_DQS_DP<8>")
	)
	(segment
		(start 84.238592 -267.035534)
		(end 84.113116 -267.16101)
		(width 0.088646)
		(layer "F.Cu")
		(net "M_A_CPU1_SA_DQS_DP<8>")
	)
	(segment
		(start 83.443064 -267.831062)
		(end 83.27009 -268.004036)
		(width 0.088646)
		(layer "F.Cu")
		(net "M_A_CPU1_SA_DQS_DP<8>")
	)
	(segment
		(start 73.66 -281.297126)
		(end 73.234042 -281.723084)
		(width 0.20066)
		(layer "F.Cu")
		(net "M_A_CPU1_SA_DQS_DP<8>")
	)
	(segment
		(start 84.51088 -266.763246)
		(end 84.364322 -266.763246)
		(width 0.088646)
		(layer "F.Cu")
		(net "M_A_CPU1_SA_DQS_DP<8>")
	)
	(segment
		(start 64.296036 -283.427932)
		(end 64.557402 -283.166566)
		(width 0.20066)
		(layer "F.Cu")
		(net "M_A_CPU1_SA_DQS_DP<8>")
	)
	(segment
		(start 62.147958 -282.730956)
		(end 62.455298 -282.730956)
		(width 0.20066)
		(layer "F.Cu")
		(net "M_A_CPU1_SA_DQS_DP<8>")
	)
	(segment
		(start 70.278498 -283.689044)
		(end 70.154038 -283.564584)
		(width 0.20066)
		(layer "F.Cu")
		(net "M_A_CPU1_SA_DQS_DP<8>")
	)
	(segment
		(start 86.309454 -266.79017)
		(end 86.177374 -266.72413)
		(width 0.088646)
		(layer "F.Cu")
		(net "M_A_CPU1_SA_DQS_DP<8>")
	)
	(segment
		(start 75.077066 -279.879806)
		(end 74.80935 -280.37536)
		(width 0.1524)
		(layer "F.Cu")
		(net "M_A_CPU1_SA_DQS_DP<8>")
	)
	(segment
		(start 63.937388 -283.427932)
		(end 64.296036 -283.427932)
		(width 0.20066)
		(layer "F.Cu")
		(net "M_A_CPU1_SA_DQS_DP<8>")
	)
	(segment
		(start 72.206612 -282.750514)
		(end 72.206612 -282.926536)
		(width 0.20066)
		(layer "F.Cu")
		(net "M_A_CPU1_SA_DQS_DP<8>")
	)
	(segment
		(start 86.44382 -267.053822)
		(end 86.309454 -266.79017)
		(width 0.088646)
		(layer "F.Cu")
		(net "M_A_CPU1_SA_DQS_DP<8>")
	)
	(segment
		(start 68.825618 -283.689044)
		(end 68.701158 -283.564584)
		(width 0.20066)
		(layer "F.Cu")
		(net "M_A_CPU1_SA_DQS_DP<8>")
	)
	(segment
		(start 84.364322 -266.763246)
		(end 84.238592 -266.888976)
		(width 0.088646)
		(layer "F.Cu")
		(net "M_A_CPU1_SA_DQS_DP<8>")
	)
	(segment
		(start 59.828684 -282.73121)
		(end 59.839352 -282.741878)
		(width 0.1016)
		(layer "F.Cu")
		(net "M_A_CPU1_SA_DQS_DP<8>")
	)
	(segment
		(start 85.715094 -266.687554)
		(end 85.715094 -266.688062)
		(width 0.088646)
		(layer "F.Cu")
		(net "M_A_CPU1_SA_DQS_DP<8>")
	)
	(segment
		(start 77.126846 -274.102576)
		(end 75.760834 -276.62505)
		(width 0.1524)
		(layer "F.Cu")
		(net "M_A_CPU1_SA_DQS_DP<8>")
	)
	(segment
		(start 85.209126 -266.68857)
		(end 84.585556 -266.68857)
		(width 0.088646)
		(layer "F.Cu")
		(net "M_A_CPU1_SA_DQS_DP<8>")
	)
	(segment
		(start 67.974718 -283.689044)
		(end 67.372738 -283.689044)
		(width 0.20066)
		(layer "F.Cu")
		(net "M_A_CPU1_SA_DQS_DP<8>")
	)
	(segment
		(start 66.153284 -283.689044)
		(end 66.038222 -283.573982)
		(width 0.20066)
		(layer "F.Cu")
		(net "M_A_CPU1_SA_DQS_DP<8>")
	)
	(segment
		(start 62.141608 -282.730956)
		(end 62.147958 -282.730956)
		(width 0.1016)
		(layer "F.Cu")
		(net "M_A_CPU1_SA_DQS_DP<8>")
	)
	(segment
		(start 83.27009 -268.004036)
		(end 83.225386 -268.004036)
		(width 0.088646)
		(layer "F.Cu")
		(net "M_A_CPU1_SA_DQS_DP<8>")
	)
	(segment
		(start 71.982838 -283.15031)
		(end 70.78853 -283.644848)
		(width 0.20066)
		(layer "F.Cu")
		(net "M_A_CPU1_SA_DQS_DP<8>")
	)
	(segment
		(start 57.977786 -283.166566)
		(end 58.21299 -283.40177)
		(width 0.20066)
		(layer "F.Cu")
		(net "M_A_CPU1_SA_DQS_DP<8>")
	)
	(segment
		(start 83.443064 -267.684504)
		(end 83.443064 -267.831062)
		(width 0.088646)
		(layer "F.Cu")
		(net "M_A_CPU1_SA_DQS_DP<8>")
	)
	(segment
		(start 83.209892 -268.01953)
		(end 77.126846 -274.102576)
		(width 0.1524)
		(layer "F.Cu")
		(net "M_A_CPU1_SA_DQS_DP<8>")
	)
	(segment
		(start 65.328038 -283.166312)
		(end 65.327784 -283.166566)
		(width 0.20066)
		(layer "F.Cu")
		(net "M_A_CPU1_SA_DQS_DP<8>")
	)
	(segment
		(start 66.038222 -283.342842)
		(end 65.861692 -283.166312)
		(width 0.20066)
		(layer "F.Cu")
		(net "M_A_CPU1_SA_DQS_DP<8>")
	)
	(segment
		(start 83.715352 -267.558774)
		(end 83.568794 -267.558774)
		(width 0.088646)
		(layer "F.Cu")
		(net "M_A_CPU1_SA_DQS_DP<8>")
	)
	(segment
		(start 84.238592 -266.888976)
		(end 84.238592 -267.035534)
		(width 0.088646)
		(layer "F.Cu")
		(net "M_A_CPU1_SA_DQS_DP<8>")
	)
	(segment
		(start 72.206612 -282.926536)
		(end 71.982838 -283.15031)
		(width 0.20066)
		(layer "F.Cu")
		(net "M_A_CPU1_SA_DQS_DP<8>")
	)
	(segment
		(start 83.225386 -268.004036)
		(end 83.209892 -268.01953)
		(width 0.088646)
		(layer "F.Cu")
		(net "M_A_CPU1_SA_DQS_DP<8>")
	)
	(segment
		(start 69.427598 -283.689044)
		(end 68.825618 -283.689044)
		(width 0.20066)
		(layer "F.Cu")
		(net "M_A_CPU1_SA_DQS_DP<8>")
	)
	(segment
		(start 83.840828 -267.28674)
		(end 83.840828 -267.433298)
		(width 0.088646)
		(layer "F.Cu")
		(net "M_A_CPU1_SA_DQS_DP<8>")
	)
	(segment
		(start 57.503314 -283.166566)
		(end 57.977786 -283.166566)
		(width 0.20066)
		(layer "F.Cu")
		(net "M_A_CPU1_SA_DQS_DP<8>")
	)
	(segment
		(start 58.871866 -283.00553)
		(end 59.338718 -283.00553)
		(width 0.20066)
		(layer "F.Cu")
		(net "M_A_CPU1_SA_DQS_DP<8>")
	)
	(segment
		(start 84.585556 -266.68857)
		(end 84.51088 -266.763246)
		(width 0.088646)
		(layer "F.Cu")
		(net "M_A_CPU1_SA_DQS_DP<8>")
	)
	(segment
		(start 65.327784 -283.166566)
		(end 65.047114 -283.166566)
		(width 0.20066)
		(layer "F.Cu")
		(net "M_A_CPU1_SA_DQS_DP<8>")
	)
	(segment
		(start 70.154038 -283.564584)
		(end 69.552058 -283.564584)
		(width 0.20066)
		(layer "F.Cu")
		(net "M_A_CPU1_SA_DQS_DP<8>")
	)
	(segment
		(start 74.80935 -280.37536)
		(end 74.339704 -280.844752)
		(width 0.1524)
		(layer "F.Cu")
		(net "M_A_CPU1_SA_DQS_DP<8>")
	)
	(segment
		(start 74.288396 -280.844752)
		(end 74.261472 -280.871676)
		(width 0.1524)
		(layer "F.Cu")
		(net "M_A_CPU1_SA_DQS_DP<8>")
	)
	(segment
		(start 69.552058 -283.564584)
		(end 69.427598 -283.689044)
		(width 0.20066)
		(layer "F.Cu")
		(net "M_A_CPU1_SA_DQS_DP<8>")
	)
	(segment
		(start 73.234042 -281.899106)
		(end 72.808592 -282.324556)
		(width 0.20066)
		(layer "F.Cu")
		(net "M_A_CPU1_SA_DQS_DP<8>")
	)
	(segment
		(start 65.861692 -283.166312)
		(end 65.328038 -283.166312)
		(width 0.20066)
		(layer "F.Cu")
		(net "M_A_CPU1_SA_DQS_DP<8>")
	)
	(segment
		(start 66.521838 -283.689044)
		(end 66.153284 -283.689044)
		(width 0.20066)
		(layer "F.Cu")
		(net "M_A_CPU1_SA_DQS_DP<8>")
	)
	(segment
		(start 74.261472 -280.871676)
		(end 73.836022 -281.297126)
		(width 0.20066)
		(layer "F.Cu")
		(net "M_A_CPU1_SA_DQS_DP<8>")
	)
	(segment
		(start 73.234042 -281.723084)
		(end 73.234042 -281.899106)
		(width 0.20066)
		(layer "F.Cu")
		(net "M_A_CPU1_SA_DQS_DP<8>")
	)
	(segment
		(start 59.338718 -283.00553)
		(end 59.613038 -282.73121)
		(width 0.20066)
		(layer "F.Cu")
		(net "M_A_CPU1_SA_DQS_DP<8>")
	)
	(segment
		(start 85.599524 -266.744704)
		(end 85.572854 -266.771628)
		(width 0.088646)
		(layer "F.Cu")
		(net "M_A_CPU1_SA_DQS_DP<8>")
	)
	(segment
		(start 59.822842 -282.73121)
		(end 59.828684 -282.73121)
		(width 0.101854)
		(layer "F.Cu")
		(net "M_A_CPU1_SA_DQS_DP<8>")
	)
	(segment
		(start 86.177374 -266.72413)
		(end 86.176866 -266.723622)
		(width 0.088646)
		(layer "F.Cu")
		(net "M_A_CPU1_SA_DQS_DP<8>")
	)
	(arc
		(start 85.715094 -266.688062)
		(mid 85.655697 -266.713092)
		(end 85.599524 -266.744704)
		(width 0.088646)
		(layer "F.Cu")
		(net "M_A_CPU1_SA_DQS_DP<8>")
	)
	(arc
		(start 86.845648 -267.219938)
		(mid 86.614016 -267.211126)
		(end 86.44382 -267.053822)
		(width 0.088646)
		(layer "F.Cu")
		(net "M_A_CPU1_SA_DQS_DP<8>")
	)
	(arc
		(start 86.176866 -266.723622)
		(mid 85.949844 -266.656161)
		(end 85.715094 -266.687554)
		(width 0.088646)
		(layer "F.Cu")
		(net "M_A_CPU1_SA_DQS_DP<8>")
	)
	(segment
		(start 76.256388 -292.4175)
		(end 76.360782 -292.313106)
		(width 0.20066)
		(layer "F.Cu")
		(net "M_A_CPU1_SA_DQS_DP<7>")
	)
	(segment
		(start 71.98487 -293.009828)
		(end 72.58685 -293.009828)
		(width 0.20066)
		(layer "F.Cu")
		(net "M_A_CPU1_SA_DQS_DP<7>")
	)
	(segment
		(start 73.43775 -293.009828)
		(end 74.826368 -293.009828)
		(width 0.20066)
		(layer "F.Cu")
		(net "M_A_CPU1_SA_DQS_DP<7>")
	)
	(segment
		(start 62.983618 -292.352984)
		(end 63.619634 -292.777926)
		(width 0.20066)
		(layer "F.Cu")
		(net "M_A_CPU1_SA_DQS_DP<7>")
	)
	(segment
		(start 58.885074 -292.355524)
		(end 59.17311 -292.355524)
		(width 0.20066)
		(layer "F.Cu")
		(net "M_A_CPU1_SA_DQS_DP<7>")
	)
	(segment
		(start 84.213954 -272.554954)
		(end 84.357718 -272.410936)
		(width 0.088646)
		(layer "F.Cu")
		(net "M_A_CPU1_SA_DQS_DP<7>")
	)
	(segment
		(start 76.962762 -291.711126)
		(end 77.388212 -291.285676)
		(width 0.20066)
		(layer "F.Cu")
		(net "M_A_CPU1_SA_DQS_DP<7>")
	)
	(segment
		(start 68.22821 -293.009828)
		(end 68.35267 -292.885368)
		(width 0.20066)
		(layer "F.Cu")
		(net "M_A_CPU1_SA_DQS_DP<7>")
	)
	(segment
		(start 77.990192 -290.683696)
		(end 78.415642 -290.258246)
		(width 0.20066)
		(layer "F.Cu")
		(net "M_A_CPU1_SA_DQS_DP<7>")
	)
	(segment
		(start 86.538308 -271.787874)
		(end 86.681818 -272.068798)
		(width 0.088646)
		(layer "F.Cu")
		(net "M_A_CPU1_SA_DQS_DP<7>")
	)
	(segment
		(start 83.380326 -273.483324)
		(end 83.42503 -273.483324)
		(width 0.088646)
		(layer "F.Cu")
		(net "M_A_CPU1_SA_DQS_DP<7>")
	)
	(segment
		(start 72.58685 -293.009828)
		(end 72.71131 -292.885368)
		(width 0.20066)
		(layer "F.Cu")
		(net "M_A_CPU1_SA_DQS_DP<7>")
	)
	(segment
		(start 85.282278 -271.787112)
		(end 85.422232 -271.787112)
		(width 0.088646)
		(layer "F.Cu")
		(net "M_A_CPU1_SA_DQS_DP<7>")
	)
	(segment
		(start 62.282578 -292.08095)
		(end 62.554612 -292.352984)
		(width 0.20066)
		(layer "F.Cu")
		(net "M_A_CPU1_SA_DQS_DP<7>")
	)
	(segment
		(start 83.786472 -272.982436)
		(end 83.930236 -272.838418)
		(width 0.088646)
		(layer "F.Cu")
		(net "M_A_CPU1_SA_DQS_DP<7>")
	)
	(segment
		(start 65.95237 -292.51656)
		(end 66.061336 -292.625526)
		(width 0.20066)
		(layer "F.Cu")
		(net "M_A_CPU1_SA_DQS_DP<7>")
	)
	(segment
		(start 68.95465 -292.885368)
		(end 69.07911 -293.009828)
		(width 0.20066)
		(layer "F.Cu")
		(net "M_A_CPU1_SA_DQS_DP<7>")
	)
	(segment
		(start 62.130686 -292.091872)
		(end 62.141608 -292.08095)
		(width 0.1016)
		(layer "F.Cu")
		(net "M_A_CPU1_SA_DQS_DP<7>")
	)
	(segment
		(start 66.77533 -293.009828)
		(end 66.89979 -292.885368)
		(width 0.20066)
		(layer "F.Cu")
		(net "M_A_CPU1_SA_DQS_DP<7>")
	)
	(segment
		(start 83.651852 -273.257264)
		(end 83.786472 -273.122644)
		(width 0.088646)
		(layer "F.Cu")
		(net "M_A_CPU1_SA_DQS_DP<7>")
	)
	(segment
		(start 73.31329 -292.885368)
		(end 73.43775 -293.009828)
		(width 0.20066)
		(layer "F.Cu")
		(net "M_A_CPU1_SA_DQS_DP<7>")
	)
	(segment
		(start 59.828684 -292.091872)
		(end 62.130686 -292.091872)
		(width 0.1016)
		(layer "F.Cu")
		(net "M_A_CPU1_SA_DQS_DP<7>")
	)
	(segment
		(start 71.13397 -293.009828)
		(end 71.25843 -292.885368)
		(width 0.20066)
		(layer "F.Cu")
		(net "M_A_CPU1_SA_DQS_DP<7>")
	)
	(segment
		(start 76.360782 -292.313106)
		(end 76.360782 -292.137084)
		(width 0.20066)
		(layer "F.Cu")
		(net "M_A_CPU1_SA_DQS_DP<7>")
	)
	(segment
		(start 76.360782 -292.137084)
		(end 76.78674 -291.711126)
		(width 0.20066)
		(layer "F.Cu")
		(net "M_A_CPU1_SA_DQS_DP<7>")
	)
	(segment
		(start 66.237358 -293.009828)
		(end 66.77533 -293.009828)
		(width 0.20066)
		(layer "F.Cu")
		(net "M_A_CPU1_SA_DQS_DP<7>")
	)
	(segment
		(start 84.925408 -271.983454)
		(end 85.008212 -271.90065)
		(width 0.088646)
		(layer "F.Cu")
		(net "M_A_CPU1_SA_DQS_DP<7>")
	)
	(segment
		(start 85.422232 -271.787112)
		(end 85.505798 -271.703546)
		(width 0.088646)
		(layer "F.Cu")
		(net "M_A_CPU1_SA_DQS_DP<7>")
	)
	(segment
		(start 78.823312 -281.567382)
		(end 79.543656 -277.965154)
		(width 0.1524)
		(layer "F.Cu")
		(net "M_A_CPU1_SA_DQS_DP<7>")
	)
	(segment
		(start 78.823312 -289.749738)
		(end 78.823312 -281.567382)
		(width 0.1524)
		(layer "F.Cu")
		(net "M_A_CPU1_SA_DQS_DP<7>")
	)
	(segment
		(start 62.554612 -292.352984)
		(end 62.983618 -292.352984)
		(width 0.20066)
		(layer "F.Cu")
		(net "M_A_CPU1_SA_DQS_DP<7>")
	)
	(segment
		(start 68.35267 -292.885368)
		(end 68.95465 -292.885368)
		(width 0.20066)
		(layer "F.Cu")
		(net "M_A_CPU1_SA_DQS_DP<7>")
	)
	(segment
		(start 86.716362 -272.103342)
		(end 86.845648 -272.103342)
		(width 0.088646)
		(layer "F.Cu")
		(net "M_A_CPU1_SA_DQS_DP<7>")
	)
	(segment
		(start 62.141608 -292.08095)
		(end 62.147958 -292.08095)
		(width 0.1016)
		(layer "F.Cu")
		(net "M_A_CPU1_SA_DQS_DP<7>")
	)
	(segment
		(start 84.641436 -272.267426)
		(end 84.641436 -272.127472)
		(width 0.088646)
		(layer "F.Cu")
		(net "M_A_CPU1_SA_DQS_DP<7>")
	)
	(segment
		(start 79.543656 -277.965154)
		(end 80.286352 -276.577298)
		(width 0.1524)
		(layer "F.Cu")
		(net "M_A_CPU1_SA_DQS_DP<7>")
	)
	(segment
		(start 66.061336 -292.833806)
		(end 66.237358 -293.009828)
		(width 0.20066)
		(layer "F.Cu")
		(net "M_A_CPU1_SA_DQS_DP<7>")
	)
	(segment
		(start 78.442566 -290.231322)
		(end 78.493874 -290.231322)
		(width 0.1524)
		(layer "F.Cu")
		(net "M_A_CPU1_SA_DQS_DP<7>")
	)
	(segment
		(start 67.50177 -292.885368)
		(end 67.62623 -293.009828)
		(width 0.20066)
		(layer "F.Cu")
		(net "M_A_CPU1_SA_DQS_DP<7>")
	)
	(segment
		(start 71.86041 -292.885368)
		(end 71.98487 -293.009828)
		(width 0.20066)
		(layer "F.Cu")
		(net "M_A_CPU1_SA_DQS_DP<7>")
	)
	(segment
		(start 77.81417 -290.683696)
		(end 77.990192 -290.683696)
		(width 0.20066)
		(layer "F.Cu")
		(net "M_A_CPU1_SA_DQS_DP<7>")
	)
	(segment
		(start 84.641436 -272.127472)
		(end 84.7852 -271.983454)
		(width 0.088646)
		(layer "F.Cu")
		(net "M_A_CPU1_SA_DQS_DP<7>")
	)
	(segment
		(start 58.239152 -292.777926)
		(end 58.462672 -292.777926)
		(width 0.20066)
		(layer "F.Cu")
		(net "M_A_CPU1_SA_DQS_DP<7>")
	)
	(segment
		(start 72.71131 -292.885368)
		(end 73.31329 -292.885368)
		(width 0.20066)
		(layer "F.Cu")
		(net "M_A_CPU1_SA_DQS_DP<7>")
	)
	(segment
		(start 64.557148 -292.516814)
		(end 65.047114 -292.516814)
		(width 0.20066)
		(layer "F.Cu")
		(net "M_A_CPU1_SA_DQS_DP<7>")
	)
	(segment
		(start 77.388212 -291.109654)
		(end 77.81417 -290.683696)
		(width 0.20066)
		(layer "F.Cu")
		(net "M_A_CPU1_SA_DQS_DP<7>")
	)
	(segment
		(start 74.826368 -293.009828)
		(end 76.256388 -292.4175)
		(width 0.20066)
		(layer "F.Cu")
		(net "M_A_CPU1_SA_DQS_DP<7>")
	)
	(segment
		(start 69.80555 -292.885368)
		(end 70.40753 -292.885368)
		(width 0.20066)
		(layer "F.Cu")
		(net "M_A_CPU1_SA_DQS_DP<7>")
	)
	(segment
		(start 66.89979 -292.885368)
		(end 67.50177 -292.885368)
		(width 0.20066)
		(layer "F.Cu")
		(net "M_A_CPU1_SA_DQS_DP<7>")
	)
	(segment
		(start 85.008212 -271.90065)
		(end 85.282278 -271.787112)
		(width 0.088646)
		(layer "F.Cu")
		(net "M_A_CPU1_SA_DQS_DP<7>")
	)
	(segment
		(start 63.619634 -292.777926)
		(end 64.296036 -292.777926)
		(width 0.20066)
		(layer "F.Cu")
		(net "M_A_CPU1_SA_DQS_DP<7>")
	)
	(segment
		(start 66.061336 -292.625526)
		(end 66.061336 -292.833806)
		(width 0.20066)
		(layer "F.Cu")
		(net "M_A_CPU1_SA_DQS_DP<7>")
	)
	(segment
		(start 64.296036 -292.777926)
		(end 64.557148 -292.516814)
		(width 0.20066)
		(layer "F.Cu")
		(net "M_A_CPU1_SA_DQS_DP<7>")
	)
	(segment
		(start 83.930236 -272.838418)
		(end 84.070444 -272.838418)
		(width 0.088646)
		(layer "F.Cu")
		(net "M_A_CPU1_SA_DQS_DP<7>")
	)
	(segment
		(start 83.364832 -273.498818)
		(end 83.380326 -273.483324)
		(width 0.088646)
		(layer "F.Cu")
		(net "M_A_CPU1_SA_DQS_DP<7>")
	)
	(segment
		(start 67.62623 -293.009828)
		(end 68.22821 -293.009828)
		(width 0.20066)
		(layer "F.Cu")
		(net "M_A_CPU1_SA_DQS_DP<7>")
	)
	(segment
		(start 83.786472 -273.122644)
		(end 83.786472 -272.982436)
		(width 0.088646)
		(layer "F.Cu")
		(net "M_A_CPU1_SA_DQS_DP<7>")
	)
	(segment
		(start 62.147958 -292.08095)
		(end 62.282578 -292.08095)
		(width 0.20066)
		(layer "F.Cu")
		(net "M_A_CPU1_SA_DQS_DP<7>")
	)
	(segment
		(start 59.442604 -292.08603)
		(end 59.822842 -292.08603)
		(width 0.20066)
		(layer "F.Cu")
		(net "M_A_CPU1_SA_DQS_DP<7>")
	)
	(segment
		(start 78.415642 -290.258246)
		(end 78.442566 -290.231322)
		(width 0.1524)
		(layer "F.Cu")
		(net "M_A_CPU1_SA_DQS_DP<7>")
	)
	(segment
		(start 69.07911 -293.009828)
		(end 69.68109 -293.009828)
		(width 0.20066)
		(layer "F.Cu")
		(net "M_A_CPU1_SA_DQS_DP<7>")
	)
	(segment
		(start 84.213954 -272.694908)
		(end 84.213954 -272.554954)
		(width 0.088646)
		(layer "F.Cu")
		(net "M_A_CPU1_SA_DQS_DP<7>")
	)
	(segment
		(start 65.047114 -292.516814)
		(end 65.952116 -292.516814)
		(width 0.20066)
		(layer "F.Cu")
		(net "M_A_CPU1_SA_DQS_DP<7>")
	)
	(segment
		(start 77.388212 -291.285676)
		(end 77.388212 -291.109654)
		(width 0.20066)
		(layer "F.Cu")
		(net "M_A_CPU1_SA_DQS_DP<7>")
	)
	(segment
		(start 84.070444 -272.838418)
		(end 84.213954 -272.694908)
		(width 0.088646)
		(layer "F.Cu")
		(net "M_A_CPU1_SA_DQS_DP<7>")
	)
	(segment
		(start 83.65109 -273.257264)
		(end 83.651852 -273.257264)
		(width 0.088646)
		(layer "F.Cu")
		(net "M_A_CPU1_SA_DQS_DP<7>")
	)
	(segment
		(start 65.952116 -292.516814)
		(end 65.95237 -292.51656)
		(width 0.20066)
		(layer "F.Cu")
		(net "M_A_CPU1_SA_DQS_DP<7>")
	)
	(segment
		(start 76.78674 -291.711126)
		(end 76.962762 -291.711126)
		(width 0.20066)
		(layer "F.Cu")
		(net "M_A_CPU1_SA_DQS_DP<7>")
	)
	(segment
		(start 59.822842 -292.08603)
		(end 59.828684 -292.091872)
		(width 0.1016)
		(layer "F.Cu")
		(net "M_A_CPU1_SA_DQS_DP<7>")
	)
	(segment
		(start 70.40753 -292.885368)
		(end 70.53199 -293.009828)
		(width 0.20066)
		(layer "F.Cu")
		(net "M_A_CPU1_SA_DQS_DP<7>")
	)
	(segment
		(start 86.176866 -271.607026)
		(end 86.177374 -271.607534)
		(width 0.088646)
		(layer "F.Cu")
		(net "M_A_CPU1_SA_DQS_DP<7>")
	)
	(segment
		(start 59.17311 -292.355524)
		(end 59.442604 -292.08603)
		(width 0.20066)
		(layer "F.Cu")
		(net "M_A_CPU1_SA_DQS_DP<7>")
	)
	(segment
		(start 58.462672 -292.777926)
		(end 58.885074 -292.355524)
		(width 0.20066)
		(layer "F.Cu")
		(net "M_A_CPU1_SA_DQS_DP<7>")
	)
	(segment
		(start 57.503314 -292.516814)
		(end 57.97804 -292.516814)
		(width 0.20066)
		(layer "F.Cu")
		(net "M_A_CPU1_SA_DQS_DP<7>")
	)
	(segment
		(start 69.68109 -293.009828)
		(end 69.80555 -292.885368)
		(width 0.20066)
		(layer "F.Cu")
		(net "M_A_CPU1_SA_DQS_DP<7>")
	)
	(segment
		(start 80.286352 -276.577298)
		(end 83.364832 -273.498818)
		(width 0.1524)
		(layer "F.Cu")
		(net "M_A_CPU1_SA_DQS_DP<7>")
	)
	(segment
		(start 78.715362 -290.009834)
		(end 78.823312 -289.749738)
		(width 0.1524)
		(layer "F.Cu")
		(net "M_A_CPU1_SA_DQS_DP<7>")
	)
	(segment
		(start 71.25843 -292.885368)
		(end 71.86041 -292.885368)
		(width 0.20066)
		(layer "F.Cu")
		(net "M_A_CPU1_SA_DQS_DP<7>")
	)
	(segment
		(start 84.7852 -271.983454)
		(end 84.925408 -271.983454)
		(width 0.088646)
		(layer "F.Cu")
		(net "M_A_CPU1_SA_DQS_DP<7>")
	)
	(segment
		(start 86.681818 -272.068798)
		(end 86.716362 -272.103342)
		(width 0.088646)
		(layer "F.Cu")
		(net "M_A_CPU1_SA_DQS_DP<7>")
	)
	(segment
		(start 57.97804 -292.516814)
		(end 58.239152 -292.777926)
		(width 0.20066)
		(layer "F.Cu")
		(net "M_A_CPU1_SA_DQS_DP<7>")
	)
	(segment
		(start 83.42503 -273.483324)
		(end 83.65109 -273.257264)
		(width 0.088646)
		(layer "F.Cu")
		(net "M_A_CPU1_SA_DQS_DP<7>")
	)
	(segment
		(start 78.493874 -290.231322)
		(end 78.715362 -290.009834)
		(width 0.1524)
		(layer "F.Cu")
		(net "M_A_CPU1_SA_DQS_DP<7>")
	)
	(segment
		(start 70.53199 -293.009828)
		(end 71.13397 -293.009828)
		(width 0.20066)
		(layer "F.Cu")
		(net "M_A_CPU1_SA_DQS_DP<7>")
	)
	(segment
		(start 84.497926 -272.410936)
		(end 84.641436 -272.267426)
		(width 0.088646)
		(layer "F.Cu")
		(net "M_A_CPU1_SA_DQS_DP<7>")
	)
	(segment
		(start 84.357718 -272.410936)
		(end 84.497926 -272.410936)
		(width 0.088646)
		(layer "F.Cu")
		(net "M_A_CPU1_SA_DQS_DP<7>")
	)
	(segment
		(start 86.177374 -271.607534)
		(end 86.538308 -271.787874)
		(width 0.088646)
		(layer "F.Cu")
		(net "M_A_CPU1_SA_DQS_DP<7>")
	)
	(arc
		(start 85.622892 -271.613884)
		(mid 85.898996 -271.537898)
		(end 86.176866 -271.607026)
		(width 0.088646)
		(layer "F.Cu")
		(net "M_A_CPU1_SA_DQS_DP<7>")
	)
	(arc
		(start 85.505798 -271.703546)
		(mid 85.561403 -271.654872)
		(end 85.622892 -271.613884)
		(width 0.088646)
		(layer "F.Cu")
		(net "M_A_CPU1_SA_DQS_DP<7>")
	)
	(segment
		(start 59.35599 -301.705518)
		(end 58.995818 -301.705518)
		(width 0.20066)
		(layer "F.Cu")
		(net "M_A_CPU1_SA_DQS_DP<6>")
	)
	(segment
		(start 65.047114 -301.866808)
		(end 64.557148 -301.866808)
		(width 0.20066)
		(layer "F.Cu")
		(net "M_A_CPU1_SA_DQS_DP<6>")
	)
	(segment
		(start 58.239152 -302.12792)
		(end 57.97804 -301.866808)
		(width 0.20066)
		(layer "F.Cu")
		(net "M_A_CPU1_SA_DQS_DP<6>")
	)
	(segment
		(start 62.550548 -301.702978)
		(end 62.289436 -301.441866)
		(width 0.20066)
		(layer "F.Cu")
		(net "M_A_CPU1_SA_DQS_DP<6>")
	)
	(segment
		(start 62.289436 -301.441866)
		(end 62.147958 -301.441866)
		(width 0.20066)
		(layer "F.Cu")
		(net "M_A_CPU1_SA_DQS_DP<6>")
	)
	(segment
		(start 64.296036 -302.12792)
		(end 63.691516 -302.12792)
		(width 0.20066)
		(layer "F.Cu")
		(net "M_A_CPU1_SA_DQS_DP<6>")
	)
	(segment
		(start 64.557148 -301.866808)
		(end 64.296036 -302.12792)
		(width 0.20066)
		(layer "F.Cu")
		(net "M_A_CPU1_SA_DQS_DP<6>")
	)
	(segment
		(start 63.0555 -301.702978)
		(end 62.550548 -301.702978)
		(width 0.20066)
		(layer "F.Cu")
		(net "M_A_CPU1_SA_DQS_DP<6>")
	)
	(segment
		(start 58.995818 -301.705518)
		(end 58.573416 -302.12792)
		(width 0.20066)
		(layer "F.Cu")
		(net "M_A_CPU1_SA_DQS_DP<6>")
	)
	(segment
		(start 57.97804 -301.866808)
		(end 57.503314 -301.866808)
		(width 0.20066)
		(layer "F.Cu")
		(net "M_A_CPU1_SA_DQS_DP<6>")
	)
	(segment
		(start 59.828684 -301.441866)
		(end 59.822842 -301.436024)
		(width 0.101854)
		(layer "F.Cu")
		(net "M_A_CPU1_SA_DQS_DP<6>")
	)
	(segment
		(start 90.134694 -269.66164)
		(end 90.134694 -270.19758)
		(width 0.20066)
		(layer "F.Cu")
		(net "M_A_CPU1_SA_DQS_DP<6>")
	)
	(segment
		(start 60.069476 -301.441866)
		(end 59.828684 -301.441866)
		(width 0.101854)
		(layer "F.Cu")
		(net "M_A_CPU1_SA_DQS_DP<6>")
	)
	(segment
		(start 63.691516 -302.12792)
		(end 63.0555 -301.702978)
		(width 0.20066)
		(layer "F.Cu")
		(net "M_A_CPU1_SA_DQS_DP<6>")
	)
	(segment
		(start 58.573416 -302.12792)
		(end 58.239152 -302.12792)
		(width 0.20066)
		(layer "F.Cu")
		(net "M_A_CPU1_SA_DQS_DP<6>")
	)
	(segment
		(start 62.147958 -301.441866)
		(end 60.069476 -301.441866)
		(width 0.1016)
		(layer "F.Cu")
		(net "M_A_CPU1_SA_DQS_DP<6>")
	)
	(segment
		(start 59.822842 -301.436024)
		(end 59.625484 -301.436024)
		(width 0.20066)
		(layer "F.Cu")
		(net "M_A_CPU1_SA_DQS_DP<6>")
	)
	(segment
		(start 66.152014 -301.866808)
		(end 65.047114 -301.866808)
		(width 0.20066)
		(layer "F.Cu")
		(net "M_A_CPU1_SA_DQS_DP<6>")
	)
	(segment
		(start 59.625484 -301.436024)
		(end 59.35599 -301.705518)
		(width 0.20066)
		(layer "F.Cu")
		(net "M_A_CPU1_SA_DQS_DP<6>")
	)
	(segment
		(start 68.081906 -295.681908)
		(end 67.69481 -296.61485)
		(width 0.18288)
		(layer "In2.Cu")
		(net "M_A_CPU1_SA_DQS_DP<6>")
	)
	(segment
		(start 66.409824 -302.124618)
		(end 66.152014 -301.866808)
		(width 0.18288)
		(layer "In2.Cu")
		(net "M_A_CPU1_SA_DQS_DP<6>")
	)
	(segment
		(start 66.995802 -301.84471)
		(end 66.716148 -302.124618)
		(width 0.18288)
		(layer "In2.Cu")
		(net "M_A_CPU1_SA_DQS_DP<6>")
	)
	(segment
		(start 89.947496 -270.521938)
		(end 89.938606 -270.516858)
		(width 0.088646)
		(layer "In2.Cu")
		(net "M_A_CPU1_SA_DQS_DP<6>")
	)
	(segment
		(start 84.49818 -270.675862)
		(end 84.414106 -270.675862)
		(width 0.088646)
		(layer "In2.Cu")
		(net "M_A_CPU1_SA_DQS_DP<6>")
	)
	(segment
		(start 81.889092 -273.200622)
		(end 80.666082 -276.152864)
		(width 0.18288)
		(layer "In2.Cu")
		(net "M_A_CPU1_SA_DQS_DP<6>")
	)
	(segment
		(start 67.681348 -300.189392)
		(end 66.995802 -301.84471)
		(width 0.18288)
		(layer "In2.Cu")
		(net "M_A_CPU1_SA_DQS_DP<6>")
	)
	(segment
		(start 67.681348 -297.332908)
		(end 67.681348 -300.189392)
		(width 0.18288)
		(layer "In2.Cu")
		(net "M_A_CPU1_SA_DQS_DP<6>")
	)
	(segment
		(start 90.330782 -270.516858)
		(end 90.321892 -270.521938)
		(width 0.088646)
		(layer "In2.Cu")
		(net "M_A_CPU1_SA_DQS_DP<6>")
	)
	(segment
		(start 90.447622 -270.19758)
		(end 90.504772 -270.25473)
		(width 0.088646)
		(layer "In2.Cu")
		(net "M_A_CPU1_SA_DQS_DP<6>")
	)
	(segment
		(start 69.935852 -291.563806)
		(end 69.726048 -292.071044)
		(width 0.18288)
		(layer "In2.Cu")
		(net "M_A_CPU1_SA_DQS_DP<6>")
	)
	(segment
		(start 70.258178 -290.78555)
		(end 70.325488 -290.94811)
		(width 0.18288)
		(layer "In2.Cu")
		(net "M_A_CPU1_SA_DQS_DP<6>")
	)
	(segment
		(start 68.781676 -294.351202)
		(end 68.571618 -294.858186)
		(width 0.18288)
		(layer "In2.Cu")
		(net "M_A_CPU1_SA_DQS_DP<6>")
	)
	(segment
		(start 89.760044 -270.19758)
		(end 89.760044 -270.179038)
		(width 0.088646)
		(layer "In2.Cu")
		(net "M_A_CPU1_SA_DQS_DP<6>")
	)
	(segment
		(start 86.845394 -269.758668)
		(end 86.657434 -269.758668)
		(width 0.088646)
		(layer "In2.Cu")
		(net "M_A_CPU1_SA_DQS_DP<6>")
	)
	(segment
		(start 75.356466 -282.89885)
		(end 72.457818 -285.797752)
		(width 0.18288)
		(layer "In2.Cu")
		(net "M_A_CPU1_SA_DQS_DP<6>")
	)
	(segment
		(start 68.424298 -295.539922)
		(end 68.081906 -295.681908)
		(width 0.18288)
		(layer "In2.Cu")
		(net "M_A_CPU1_SA_DQS_DP<6>")
	)
	(segment
		(start 70.467982 -290.278566)
		(end 70.258178 -290.78555)
		(width 0.18288)
		(layer "In2.Cu")
		(net "M_A_CPU1_SA_DQS_DP<6>")
	)
	(segment
		(start 85.893656 -270.522446)
		(end 84.704428 -270.522446)
		(width 0.088646)
		(layer "In2.Cu")
		(net "M_A_CPU1_SA_DQS_DP<6>")
	)
	(segment
		(start 90.134694 -270.19758)
		(end 90.447622 -270.19758)
		(width 0.088646)
		(layer "In2.Cu")
		(net "M_A_CPU1_SA_DQS_DP<6>")
	)
	(segment
		(start 72.457818 -285.797752)
		(end 70.630796 -290.211002)
		(width 0.18288)
		(layer "In2.Cu")
		(net "M_A_CPU1_SA_DQS_DP<6>")
	)
	(segment
		(start 67.69481 -296.61485)
		(end 67.83705 -296.956988)
		(width 0.18288)
		(layer "In2.Cu")
		(net "M_A_CPU1_SA_DQS_DP<6>")
	)
	(segment
		(start 70.098666 -291.496496)
		(end 69.935852 -291.563806)
		(width 0.18288)
		(layer "In2.Cu")
		(net "M_A_CPU1_SA_DQS_DP<6>")
	)
	(segment
		(start 69.793358 -292.233604)
		(end 69.459602 -293.0398)
		(width 0.18288)
		(layer "In2.Cu")
		(net "M_A_CPU1_SA_DQS_DP<6>")
	)
	(segment
		(start 68.571618 -294.858186)
		(end 68.639182 -295.020746)
		(width 0.18288)
		(layer "In2.Cu")
		(net "M_A_CPU1_SA_DQS_DP<6>")
	)
	(segment
		(start 86.657434 -269.758668)
		(end 85.893656 -270.522446)
		(width 0.088646)
		(layer "In2.Cu")
		(net "M_A_CPU1_SA_DQS_DP<6>")
	)
	(segment
		(start 68.94449 -294.283638)
		(end 68.781676 -294.351202)
		(width 0.18288)
		(layer "In2.Cu")
		(net "M_A_CPU1_SA_DQS_DP<6>")
	)
	(segment
		(start 69.154294 -293.776908)
		(end 68.94449 -294.283638)
		(width 0.18288)
		(layer "In2.Cu")
		(net "M_A_CPU1_SA_DQS_DP<6>")
	)
	(segment
		(start 84.704428 -270.522446)
		(end 84.614512 -270.55953)
		(width 0.088646)
		(layer "In2.Cu")
		(net "M_A_CPU1_SA_DQS_DP<6>")
	)
	(segment
		(start 69.459602 -293.0398)
		(end 69.296788 -293.10711)
		(width 0.18288)
		(layer "In2.Cu")
		(net "M_A_CPU1_SA_DQS_DP<6>")
	)
	(segment
		(start 84.414106 -270.675862)
		(end 81.889092 -273.200622)
		(width 0.18288)
		(layer "In2.Cu")
		(net "M_A_CPU1_SA_DQS_DP<6>")
	)
	(segment
		(start 80.666082 -276.152864)
		(end 76.371958 -280.446988)
		(width 0.18288)
		(layer "In2.Cu")
		(net "M_A_CPU1_SA_DQS_DP<6>")
	)
	(segment
		(start 69.08673 -293.614348)
		(end 69.154294 -293.776908)
		(width 0.18288)
		(layer "In2.Cu")
		(net "M_A_CPU1_SA_DQS_DP<6>")
	)
	(segment
		(start 70.630796 -290.211002)
		(end 70.467982 -290.278566)
		(width 0.18288)
		(layer "In2.Cu")
		(net "M_A_CPU1_SA_DQS_DP<6>")
	)
	(segment
		(start 84.614512 -270.55953)
		(end 84.49818 -270.675862)
		(width 0.088646)
		(layer "In2.Cu")
		(net "M_A_CPU1_SA_DQS_DP<6>")
	)
	(segment
		(start 67.83705 -296.956988)
		(end 67.681348 -297.332908)
		(width 0.18288)
		(layer "In2.Cu")
		(net "M_A_CPU1_SA_DQS_DP<6>")
	)
	(segment
		(start 87.032592 -269.707868)
		(end 87.0331 -269.708376)
		(width 0.088646)
		(layer "In2.Cu")
		(net "M_A_CPU1_SA_DQS_DP<6>")
	)
	(segment
		(start 76.371958 -280.446988)
		(end 75.356466 -282.89885)
		(width 0.18288)
		(layer "In2.Cu")
		(net "M_A_CPU1_SA_DQS_DP<6>")
	)
	(segment
		(start 69.726048 -292.071044)
		(end 69.793358 -292.233604)
		(width 0.18288)
		(layer "In2.Cu")
		(net "M_A_CPU1_SA_DQS_DP<6>")
	)
	(segment
		(start 69.296788 -293.10711)
		(end 69.08673 -293.614348)
		(width 0.18288)
		(layer "In2.Cu")
		(net "M_A_CPU1_SA_DQS_DP<6>")
	)
	(segment
		(start 70.325488 -290.94811)
		(end 70.098666 -291.496496)
		(width 0.18288)
		(layer "In2.Cu")
		(net "M_A_CPU1_SA_DQS_DP<6>")
	)
	(segment
		(start 66.716148 -302.124618)
		(end 66.409824 -302.124618)
		(width 0.18288)
		(layer "In2.Cu")
		(net "M_A_CPU1_SA_DQS_DP<6>")
	)
	(segment
		(start 68.639182 -295.020746)
		(end 68.424298 -295.539922)
		(width 0.18288)
		(layer "In2.Cu")
		(net "M_A_CPU1_SA_DQS_DP<6>")
	)
	(arc
		(start 87.972392 -269.707868)
		(mid 87.785194 -269.758011)
		(end 87.597996 -269.707868)
		(width 0.088646)
		(layer "In2.Cu")
		(net "M_A_CPU1_SA_DQS_DP<6>")
	)
	(arc
		(start 87.0331 -269.708376)
		(mid 86.942558 -269.745879)
		(end 86.845394 -269.758668)
		(width 0.088646)
		(layer "In2.Cu")
		(net "M_A_CPU1_SA_DQS_DP<6>")
	)
	(arc
		(start 88.537796 -269.707868)
		(mid 88.255094 -269.632126)
		(end 87.972392 -269.707868)
		(width 0.088646)
		(layer "In2.Cu")
		(net "M_A_CPU1_SA_DQS_DP<6>")
	)
	(arc
		(start 90.504772 -270.25473)
		(mid 90.446653 -270.404971)
		(end 90.330782 -270.516858)
		(width 0.088646)
		(layer "In2.Cu")
		(net "M_A_CPU1_SA_DQS_DP<6>")
	)
	(arc
		(start 87.597996 -269.707868)
		(mid 87.315294 -269.632126)
		(end 87.032592 -269.707868)
		(width 0.088646)
		(layer "In2.Cu")
		(net "M_A_CPU1_SA_DQS_DP<6>")
	)
	(arc
		(start 89.477596 -269.707868)
		(mid 89.194894 -269.632126)
		(end 88.912192 -269.707868)
		(width 0.088646)
		(layer "In2.Cu")
		(net "M_A_CPU1_SA_DQS_DP<6>")
	)
	(arc
		(start 89.760044 -270.179038)
		(mid 89.679882 -269.906849)
		(end 89.477596 -269.707868)
		(width 0.088646)
		(layer "In2.Cu")
		(net "M_A_CPU1_SA_DQS_DP<6>")
	)
	(arc
		(start 89.938606 -270.516858)
		(mid 89.807692 -270.380498)
		(end 89.760044 -270.19758)
		(width 0.088646)
		(layer "In2.Cu")
		(net "M_A_CPU1_SA_DQS_DP<6>")
	)
	(arc
		(start 90.321892 -270.521938)
		(mid 90.134694 -270.572081)
		(end 89.947496 -270.521938)
		(width 0.088646)
		(layer "In2.Cu")
		(net "M_A_CPU1_SA_DQS_DP<6>")
	)
	(arc
		(start 88.912192 -269.707868)
		(mid 88.724994 -269.758011)
		(end 88.537796 -269.707868)
		(width 0.088646)
		(layer "In2.Cu")
		(net "M_A_CPU1_SA_DQS_DP<6>")
	)
	(segment
		(start 82.734912 -295.887394)
		(end 82.317336 -296.898568)
		(width 0.1524)
		(layer "F.Cu")
		(net "M_A_CPU1_SA_DQS_DP<5>")
	)
	(segment
		(start 72.567546 -305.925982)
		(end 72.550274 -306.101242)
		(width 0.20066)
		(layer "F.Cu")
		(net "M_A_CPU1_SA_DQS_DP<5>")
	)
	(segment
		(start 65.85077 -311.475882)
		(end 65.591436 -311.216548)
		(width 0.20066)
		(layer "F.Cu")
		(net "M_A_CPU1_SA_DQS_DP<5>")
	)
	(segment
		(start 71.444358 -306.848002)
		(end 71.427086 -307.023008)
		(width 0.20066)
		(layer "F.Cu")
		(net "M_A_CPU1_SA_DQS_DP<5>")
	)
	(segment
		(start 81.853786 -297.401488)
		(end 81.826862 -297.428412)
		(width 0.1524)
		(layer "F.Cu")
		(net "M_A_CPU1_SA_DQS_DP<5>")
	)
	(segment
		(start 65.591436 -311.216548)
		(end 65.591182 -311.216802)
		(width 0.20066)
		(layer "F.Cu")
		(net "M_A_CPU1_SA_DQS_DP<5>")
	)
	(segment
		(start 81.826862 -297.428412)
		(end 75.919838 -303.335436)
		(width 0.20066)
		(layer "F.Cu")
		(net "M_A_CPU1_SA_DQS_DP<5>")
	)
	(segment
		(start 82.13344 -297.17365)
		(end 81.905602 -297.401488)
		(width 0.1524)
		(layer "F.Cu")
		(net "M_A_CPU1_SA_DQS_DP<5>")
	)
	(segment
		(start 73.033128 -305.543712)
		(end 72.567546 -305.925982)
		(width 0.20066)
		(layer "F.Cu")
		(net "M_A_CPU1_SA_DQS_DP<5>")
	)
	(segment
		(start 84.09686 -278.591264)
		(end 83.324446 -279.363678)
		(width 0.1524)
		(layer "F.Cu")
		(net "M_A_CPU1_SA_DQS_DP<5>")
	)
	(segment
		(start 82.734912 -282.328366)
		(end 82.734912 -295.887394)
		(width 0.1524)
		(layer "F.Cu")
		(net "M_A_CPU1_SA_DQS_DP<5>")
	)
	(segment
		(start 66.220848 -311.475882)
		(end 65.85077 -311.475882)
		(width 0.20066)
		(layer "F.Cu")
		(net "M_A_CPU1_SA_DQS_DP<5>")
	)
	(segment
		(start 85.435694 -277.235158)
		(end 85.242654 -277.235158)
		(width 0.088646)
		(layer "F.Cu")
		(net "M_A_CPU1_SA_DQS_DP<5>")
	)
	(segment
		(start 82.317336 -296.898568)
		(end 82.13344 -297.17365)
		(width 0.1524)
		(layer "F.Cu")
		(net "M_A_CPU1_SA_DQS_DP<5>")
	)
	(segment
		(start 72.550274 -306.101242)
		(end 72.0852 -306.483004)
		(width 0.20066)
		(layer "F.Cu")
		(net "M_A_CPU1_SA_DQS_DP<5>")
	)
	(segment
		(start 62.455298 -310.780938)
		(end 62.727332 -311.052972)
		(width 0.20066)
		(layer "F.Cu")
		(net "M_A_CPU1_SA_DQS_DP<5>")
	)
	(segment
		(start 66.769488 -311.248298)
		(end 66.76898 -311.248552)
		(width 0.20066)
		(layer "F.Cu")
		(net "M_A_CPU1_SA_DQS_DP<5>")
	)
	(segment
		(start 87.128096 -278.12492)
		(end 87.126572 -278.124158)
		(width 0.088646)
		(layer "F.Cu")
		(net "M_A_CPU1_SA_DQS_DP<5>")
	)
	(segment
		(start 74.813922 -304.082196)
		(end 74.79665 -304.257456)
		(width 0.20066)
		(layer "F.Cu")
		(net "M_A_CPU1_SA_DQS_DP<5>")
	)
	(segment
		(start 87.315294 -277.800562)
		(end 87.62619 -277.800562)
		(width 0.088646)
		(layer "F.Cu")
		(net "M_A_CPU1_SA_DQS_DP<5>")
	)
	(segment
		(start 84.879688 -277.50389)
		(end 84.799678 -277.696676)
		(width 0.088646)
		(layer "F.Cu")
		(net "M_A_CPU1_SA_DQS_DP<5>")
	)
	(segment
		(start 58.239152 -311.477914)
		(end 58.462672 -311.477914)
		(width 0.20066)
		(layer "F.Cu")
		(net "M_A_CPU1_SA_DQS_DP<5>")
	)
	(segment
		(start 84.799678 -277.696676)
		(end 84.337906 -278.158702)
		(width 0.088646)
		(layer "F.Cu")
		(net "M_A_CPU1_SA_DQS_DP<5>")
	)
	(segment
		(start 59.442604 -310.786018)
		(end 59.822842 -310.786018)
		(width 0.20066)
		(layer "F.Cu")
		(net "M_A_CPU1_SA_DQS_DP<5>")
	)
	(segment
		(start 59.822842 -310.786018)
		(end 59.828684 -310.79186)
		(width 0.1016)
		(layer "F.Cu")
		(net "M_A_CPU1_SA_DQS_DP<5>")
	)
	(segment
		(start 64.296036 -311.477914)
		(end 64.557148 -311.216802)
		(width 0.20066)
		(layer "F.Cu")
		(net "M_A_CPU1_SA_DQS_DP<5>")
	)
	(segment
		(start 62.130686 -310.79186)
		(end 62.141608 -310.780938)
		(width 0.1016)
		(layer "F.Cu")
		(net "M_A_CPU1_SA_DQS_DP<5>")
	)
	(segment
		(start 58.885074 -311.055512)
		(end 59.17311 -311.055512)
		(width 0.20066)
		(layer "F.Cu")
		(net "M_A_CPU1_SA_DQS_DP<5>")
	)
	(segment
		(start 66.977514 -311.162446)
		(end 66.769488 -311.248298)
		(width 0.20066)
		(layer "F.Cu")
		(net "M_A_CPU1_SA_DQS_DP<5>")
	)
	(segment
		(start 74.156316 -304.621946)
		(end 73.690734 -305.004216)
		(width 0.20066)
		(layer "F.Cu")
		(net "M_A_CPU1_SA_DQS_DP<5>")
	)
	(segment
		(start 75.454764 -303.717198)
		(end 75.279504 -303.699926)
		(width 0.20066)
		(layer "F.Cu")
		(net "M_A_CPU1_SA_DQS_DP<5>")
	)
	(segment
		(start 73.673462 -305.179222)
		(end 73.208388 -305.560984)
		(width 0.20066)
		(layer "F.Cu")
		(net "M_A_CPU1_SA_DQS_DP<5>")
	)
	(segment
		(start 84.112354 -278.57577)
		(end 84.09686 -278.591264)
		(width 0.088646)
		(layer "F.Cu")
		(net "M_A_CPU1_SA_DQS_DP<5>")
	)
	(segment
		(start 85.081872 -277.301706)
		(end 84.879688 -277.50389)
		(width 0.088646)
		(layer "F.Cu")
		(net "M_A_CPU1_SA_DQS_DP<5>")
	)
	(segment
		(start 83.324446 -279.363932)
		(end 82.734912 -282.328366)
		(width 0.1524)
		(layer "F.Cu")
		(net "M_A_CPU1_SA_DQS_DP<5>")
	)
	(segment
		(start 83.324446 -279.363678)
		(end 83.324446 -279.363932)
		(width 0.1524)
		(layer "F.Cu")
		(net "M_A_CPU1_SA_DQS_DP<5>")
	)
	(segment
		(start 62.147958 -310.780938)
		(end 62.455298 -310.780938)
		(width 0.20066)
		(layer "F.Cu")
		(net "M_A_CPU1_SA_DQS_DP<5>")
	)
	(segment
		(start 71.90994 -306.465732)
		(end 71.444358 -306.848002)
		(width 0.20066)
		(layer "F.Cu")
		(net "M_A_CPU1_SA_DQS_DP<5>")
	)
	(segment
		(start 87.62619 -277.800562)
		(end 87.685118 -277.85949)
		(width 0.088646)
		(layer "F.Cu")
		(net "M_A_CPU1_SA_DQS_DP<5>")
	)
	(segment
		(start 67.284346 -311.0357)
		(end 66.977514 -311.162446)
		(width 0.20066)
		(layer "F.Cu")
		(net "M_A_CPU1_SA_DQS_DP<5>")
	)
	(segment
		(start 81.905602 -297.401488)
		(end 81.853786 -297.401488)
		(width 0.1524)
		(layer "F.Cu")
		(net "M_A_CPU1_SA_DQS_DP<5>")
	)
	(segment
		(start 86.103206 -277.304754)
		(end 86.092792 -277.31085)
		(width 0.088646)
		(layer "F.Cu")
		(net "M_A_CPU1_SA_DQS_DP<5>")
	)
	(segment
		(start 74.331576 -304.639218)
		(end 74.156316 -304.621946)
		(width 0.20066)
		(layer "F.Cu")
		(net "M_A_CPU1_SA_DQS_DP<5>")
	)
	(segment
		(start 86.940644 -277.800562)
		(end 86.940644 -277.778464)
		(width 0.088646)
		(layer "F.Cu")
		(net "M_A_CPU1_SA_DQS_DP<5>")
	)
	(segment
		(start 66.76898 -311.248552)
		(end 66.220848 -311.475882)
		(width 0.20066)
		(layer "F.Cu")
		(net "M_A_CPU1_SA_DQS_DP<5>")
	)
	(segment
		(start 73.208388 -305.560984)
		(end 73.033128 -305.543712)
		(width 0.20066)
		(layer "F.Cu")
		(net "M_A_CPU1_SA_DQS_DP<5>")
	)
	(segment
		(start 84.337906 -278.158702)
		(end 84.221574 -278.511762)
		(width 0.088646)
		(layer "F.Cu")
		(net "M_A_CPU1_SA_DQS_DP<5>")
	)
	(segment
		(start 75.919838 -303.335436)
		(end 75.454764 -303.717198)
		(width 0.20066)
		(layer "F.Cu")
		(net "M_A_CPU1_SA_DQS_DP<5>")
	)
	(segment
		(start 85.242654 -277.235158)
		(end 85.081872 -277.301706)
		(width 0.088646)
		(layer "F.Cu")
		(net "M_A_CPU1_SA_DQS_DP<5>")
	)
	(segment
		(start 84.157566 -278.57577)
		(end 84.112354 -278.57577)
		(width 0.088646)
		(layer "F.Cu")
		(net "M_A_CPU1_SA_DQS_DP<5>")
	)
	(segment
		(start 63.937388 -311.477914)
		(end 64.296036 -311.477914)
		(width 0.20066)
		(layer "F.Cu")
		(net "M_A_CPU1_SA_DQS_DP<5>")
	)
	(segment
		(start 64.557148 -311.216802)
		(end 65.047114 -311.216802)
		(width 0.20066)
		(layer "F.Cu")
		(net "M_A_CPU1_SA_DQS_DP<5>")
	)
	(segment
		(start 58.462672 -311.477914)
		(end 58.885074 -311.055512)
		(width 0.20066)
		(layer "F.Cu")
		(net "M_A_CPU1_SA_DQS_DP<5>")
	)
	(segment
		(start 74.79665 -304.257456)
		(end 74.331576 -304.639218)
		(width 0.20066)
		(layer "F.Cu")
		(net "M_A_CPU1_SA_DQS_DP<5>")
	)
	(segment
		(start 87.511382 -278.11984)
		(end 87.502492 -278.12492)
		(width 0.088646)
		(layer "F.Cu")
		(net "M_A_CPU1_SA_DQS_DP<5>")
	)
	(segment
		(start 75.279504 -303.699926)
		(end 74.813922 -304.082196)
		(width 0.20066)
		(layer "F.Cu")
		(net "M_A_CPU1_SA_DQS_DP<5>")
	)
	(segment
		(start 57.503314 -311.216802)
		(end 57.97804 -311.216802)
		(width 0.20066)
		(layer "F.Cu")
		(net "M_A_CPU1_SA_DQS_DP<5>")
	)
	(segment
		(start 59.828684 -310.79186)
		(end 62.130686 -310.79186)
		(width 0.1016)
		(layer "F.Cu")
		(net "M_A_CPU1_SA_DQS_DP<5>")
	)
	(segment
		(start 71.427086 -307.023008)
		(end 70.699884 -307.619908)
		(width 0.20066)
		(layer "F.Cu")
		(net "M_A_CPU1_SA_DQS_DP<5>")
	)
	(segment
		(start 57.97804 -311.216802)
		(end 58.239152 -311.477914)
		(width 0.20066)
		(layer "F.Cu")
		(net "M_A_CPU1_SA_DQS_DP<5>")
	)
	(segment
		(start 84.221574 -278.511762)
		(end 84.157566 -278.57577)
		(width 0.088646)
		(layer "F.Cu")
		(net "M_A_CPU1_SA_DQS_DP<5>")
	)
	(segment
		(start 72.0852 -306.483004)
		(end 71.90994 -306.465732)
		(width 0.20066)
		(layer "F.Cu")
		(net "M_A_CPU1_SA_DQS_DP<5>")
	)
	(segment
		(start 65.591182 -311.216802)
		(end 65.047114 -311.216802)
		(width 0.20066)
		(layer "F.Cu")
		(net "M_A_CPU1_SA_DQS_DP<5>")
	)
	(segment
		(start 62.727332 -311.052972)
		(end 63.301372 -311.052972)
		(width 0.20066)
		(layer "F.Cu")
		(net "M_A_CPU1_SA_DQS_DP<5>")
	)
	(segment
		(start 70.699884 -307.619908)
		(end 67.284346 -311.0357)
		(width 0.20066)
		(layer "F.Cu")
		(net "M_A_CPU1_SA_DQS_DP<5>")
	)
	(segment
		(start 87.126572 -278.124158)
		(end 87.119206 -278.11984)
		(width 0.088646)
		(layer "F.Cu")
		(net "M_A_CPU1_SA_DQS_DP<5>")
	)
	(segment
		(start 62.141608 -310.780938)
		(end 62.147958 -310.780938)
		(width 0.1016)
		(layer "F.Cu")
		(net "M_A_CPU1_SA_DQS_DP<5>")
	)
	(segment
		(start 73.690734 -305.004216)
		(end 73.673462 -305.179222)
		(width 0.20066)
		(layer "F.Cu")
		(net "M_A_CPU1_SA_DQS_DP<5>")
	)
	(segment
		(start 63.301372 -311.052972)
		(end 63.937388 -311.477914)
		(width 0.20066)
		(layer "F.Cu")
		(net "M_A_CPU1_SA_DQS_DP<5>")
	)
	(segment
		(start 59.17311 -311.055512)
		(end 59.442604 -310.786018)
		(width 0.20066)
		(layer "F.Cu")
		(net "M_A_CPU1_SA_DQS_DP<5>")
	)
	(arc
		(start 87.502492 -278.12492)
		(mid 87.315294 -278.175063)
		(end 87.128096 -278.12492)
		(width 0.088646)
		(layer "F.Cu")
		(net "M_A_CPU1_SA_DQS_DP<5>")
	)
	(arc
		(start 85.718396 -277.31085)
		(mid 85.58203 -277.254372)
		(end 85.435694 -277.235158)
		(width 0.088646)
		(layer "F.Cu")
		(net "M_A_CPU1_SA_DQS_DP<5>")
	)
	(arc
		(start 87.119206 -278.11984)
		(mid 86.988292 -277.98348)
		(end 86.940644 -277.800562)
		(width 0.088646)
		(layer "F.Cu")
		(net "M_A_CPU1_SA_DQS_DP<5>")
	)
	(arc
		(start 87.685118 -277.85949)
		(mid 87.626775 -278.008713)
		(end 87.511382 -278.11984)
		(width 0.088646)
		(layer "F.Cu")
		(net "M_A_CPU1_SA_DQS_DP<5>")
	)
	(arc
		(start 86.940644 -277.778464)
		(mid 86.859733 -277.508336)
		(end 86.65845 -277.31085)
		(width 0.088646)
		(layer "F.Cu")
		(net "M_A_CPU1_SA_DQS_DP<5>")
	)
	(arc
		(start 86.65845 -277.31085)
		(mid 86.381637 -277.235014)
		(end 86.103206 -277.304754)
		(width 0.088646)
		(layer "F.Cu")
		(net "M_A_CPU1_SA_DQS_DP<5>")
	)
	(arc
		(start 86.092792 -277.31085)
		(mid 85.905594 -277.360993)
		(end 85.718396 -277.31085)
		(width 0.088646)
		(layer "F.Cu")
		(net "M_A_CPU1_SA_DQS_DP<5>")
	)
	(segment
		(start 60.137294 -275.255482)
		(end 60.398406 -275.516594)
		(width 0.20066)
		(layer "F.Cu")
		(net "M_A_CPU1_SA_DQS_DP<4>")
	)
	(segment
		(start 53.941218 -275.516594)
		(end 54.20233 -275.255482)
		(width 0.20066)
		(layer "F.Cu")
		(net "M_A_CPU1_SA_DQS_DP<4>")
	)
	(segment
		(start 85.181186 -262.636762)
		(end 84.923884 -262.68807)
		(width 0.088646)
		(layer "F.Cu")
		(net "M_A_CPU1_SA_DQS_DP<4>")
	)
	(segment
		(start 55.702454 -275.680678)
		(end 55.963566 -275.94179)
		(width 0.20066)
		(layer "F.Cu")
		(net "M_A_CPU1_SA_DQS_DP<4>")
	)
	(segment
		(start 84.864194 -262.68807)
		(end 84.399628 -262.880348)
		(width 0.088646)
		(layer "F.Cu")
		(net "M_A_CPU1_SA_DQS_DP<4>")
	)
	(segment
		(start 55.963566 -275.94179)
		(end 56.036464 -275.94179)
		(width 0.20066)
		(layer "F.Cu")
		(net "M_A_CPU1_SA_DQS_DP<4>")
	)
	(segment
		(start 60.398406 -275.516594)
		(end 60.947046 -275.516594)
		(width 0.20066)
		(layer "F.Cu")
		(net "M_A_CPU1_SA_DQS_DP<4>")
	)
	(segment
		(start 59.271154 -275.680678)
		(end 59.565286 -275.558758)
		(width 0.20066)
		(layer "F.Cu")
		(net "M_A_CPU1_SA_DQS_DP<4>")
	)
	(segment
		(start 75.765914 -269.063724)
		(end 75.73899 -269.090648)
		(width 0.1524)
		(layer "F.Cu")
		(net "M_A_CPU1_SA_DQS_DP<4>")
	)
	(segment
		(start 59.117484 -275.680678)
		(end 59.271154 -275.680678)
		(width 0.20066)
		(layer "F.Cu")
		(net "M_A_CPU1_SA_DQS_DP<4>")
	)
	(segment
		(start 59.565286 -275.558758)
		(end 59.868562 -275.255482)
		(width 0.20066)
		(layer "F.Cu")
		(net "M_A_CPU1_SA_DQS_DP<4>")
	)
	(segment
		(start 58.744612 -275.94179)
		(end 58.856372 -275.94179)
		(width 0.20066)
		(layer "F.Cu")
		(net "M_A_CPU1_SA_DQS_DP<4>")
	)
	(segment
		(start 85.905594 -262.336534)
		(end 85.181186 -262.636762)
		(width 0.088646)
		(layer "F.Cu")
		(net "M_A_CPU1_SA_DQS_DP<4>")
	)
	(segment
		(start 63.414656 -275.686774)
		(end 62.857634 -275.686774)
		(width 0.20066)
		(layer "F.Cu")
		(net "M_A_CPU1_SA_DQS_DP<4>")
	)
	(segment
		(start 58.856372 -275.94179)
		(end 59.117484 -275.680678)
		(width 0.20066)
		(layer "F.Cu")
		(net "M_A_CPU1_SA_DQS_DP<4>")
	)
	(segment
		(start 61.840364 -275.265388)
		(end 61.691012 -275.265388)
		(width 0.20066)
		(layer "F.Cu")
		(net "M_A_CPU1_SA_DQS_DP<4>")
	)
	(segment
		(start 54.479444 -275.255482)
		(end 55.11546 -275.680678)
		(width 0.20066)
		(layer "F.Cu")
		(net "M_A_CPU1_SA_DQS_DP<4>")
	)
	(segment
		(start 66.308224 -275.941536)
		(end 63.815722 -275.941536)
		(width 0.1016)
		(layer "F.Cu")
		(net "M_A_CPU1_SA_DQS_DP<4>")
	)
	(segment
		(start 55.11546 -275.680678)
		(end 55.702454 -275.680678)
		(width 0.20066)
		(layer "F.Cu")
		(net "M_A_CPU1_SA_DQS_DP<4>")
	)
	(segment
		(start 69.03339 -275.41728)
		(end 68.108322 -275.800312)
		(width 0.20066)
		(layer "F.Cu")
		(net "M_A_CPU1_SA_DQS_DP<4>")
	)
	(segment
		(start 63.669418 -275.941536)
		(end 63.414656 -275.686774)
		(width 0.20066)
		(layer "F.Cu")
		(net "M_A_CPU1_SA_DQS_DP<4>")
	)
	(segment
		(start 70.175374 -274.654264)
		(end 69.03339 -275.41728)
		(width 0.20066)
		(layer "F.Cu")
		(net "M_A_CPU1_SA_DQS_DP<4>")
	)
	(segment
		(start 54.20233 -275.255482)
		(end 54.479444 -275.255482)
		(width 0.20066)
		(layer "F.Cu")
		(net "M_A_CPU1_SA_DQS_DP<4>")
	)
	(segment
		(start 82.44586 -262.912352)
		(end 76.92009 -268.438122)
		(width 0.1524)
		(layer "F.Cu")
		(net "M_A_CPU1_SA_DQS_DP<4>")
	)
	(segment
		(start 66.567558 -275.800312)
		(end 66.426334 -275.941536)
		(width 0.20066)
		(layer "F.Cu")
		(net "M_A_CPU1_SA_DQS_DP<4>")
	)
	(segment
		(start 53.403246 -275.516594)
		(end 53.941218 -275.516594)
		(width 0.20066)
		(layer "F.Cu")
		(net "M_A_CPU1_SA_DQS_DP<4>")
	)
	(segment
		(start 68.108322 -275.800312)
		(end 66.567558 -275.800312)
		(width 0.20066)
		(layer "F.Cu")
		(net "M_A_CPU1_SA_DQS_DP<4>")
	)
	(segment
		(start 63.815722 -275.941536)
		(end 63.669418 -275.941536)
		(width 0.20066)
		(layer "F.Cu")
		(net "M_A_CPU1_SA_DQS_DP<4>")
	)
	(segment
		(start 66.426334 -275.941536)
		(end 66.308224 -275.941536)
		(width 0.20066)
		(layer "F.Cu")
		(net "M_A_CPU1_SA_DQS_DP<4>")
	)
	(segment
		(start 82.756502 -262.912352)
		(end 82.734404 -262.912352)
		(width 0.088646)
		(layer "F.Cu")
		(net "M_A_CPU1_SA_DQS_DP<4>")
	)
	(segment
		(start 61.691012 -275.265388)
		(end 61.439806 -275.516594)
		(width 0.20066)
		(layer "F.Cu")
		(net "M_A_CPU1_SA_DQS_DP<4>")
	)
	(segment
		(start 84.923884 -262.68807)
		(end 84.864194 -262.68807)
		(width 0.088646)
		(layer "F.Cu")
		(net "M_A_CPU1_SA_DQS_DP<4>")
	)
	(segment
		(start 75.73899 -269.090648)
		(end 70.175374 -274.654264)
		(width 0.20066)
		(layer "F.Cu")
		(net "M_A_CPU1_SA_DQS_DP<4>")
	)
	(segment
		(start 82.734404 -262.912352)
		(end 82.44586 -262.912352)
		(width 0.1524)
		(layer "F.Cu")
		(net "M_A_CPU1_SA_DQS_DP<4>")
	)
	(segment
		(start 82.788506 -262.880348)
		(end 82.756502 -262.912352)
		(width 0.088646)
		(layer "F.Cu")
		(net "M_A_CPU1_SA_DQS_DP<4>")
	)
	(segment
		(start 76.92009 -268.438122)
		(end 76.339192 -268.438122)
		(width 0.1524)
		(layer "F.Cu")
		(net "M_A_CPU1_SA_DQS_DP<4>")
	)
	(segment
		(start 75.765914 -269.0114)
		(end 75.765914 -269.063724)
		(width 0.1524)
		(layer "F.Cu")
		(net "M_A_CPU1_SA_DQS_DP<4>")
	)
	(segment
		(start 56.036464 -275.94179)
		(end 58.744612 -275.94179)
		(width 0.1016)
		(layer "F.Cu")
		(net "M_A_CPU1_SA_DQS_DP<4>")
	)
	(segment
		(start 61.439806 -275.516594)
		(end 60.947046 -275.516594)
		(width 0.20066)
		(layer "F.Cu")
		(net "M_A_CPU1_SA_DQS_DP<4>")
	)
	(segment
		(start 84.399628 -262.880348)
		(end 82.788506 -262.880348)
		(width 0.088646)
		(layer "F.Cu")
		(net "M_A_CPU1_SA_DQS_DP<4>")
	)
	(segment
		(start 76.339192 -268.438122)
		(end 75.765914 -269.0114)
		(width 0.1524)
		(layer "F.Cu")
		(net "M_A_CPU1_SA_DQS_DP<4>")
	)
	(segment
		(start 62.857634 -275.686774)
		(end 61.840364 -275.265388)
		(width 0.20066)
		(layer "F.Cu")
		(net "M_A_CPU1_SA_DQS_DP<4>")
	)
	(segment
		(start 59.868562 -275.255482)
		(end 60.137294 -275.255482)
		(width 0.20066)
		(layer "F.Cu")
		(net "M_A_CPU1_SA_DQS_DP<4>")
	)
	(segment
		(start 58.899044 -285.291784)
		(end 59.160156 -285.030672)
		(width 0.20066)
		(layer "F.Cu")
		(net "M_A_CPU1_SA_DQS_DP<3>")
	)
	(segment
		(start 59.552078 -285.030672)
		(end 59.977274 -284.605476)
		(width 0.20066)
		(layer "F.Cu")
		(net "M_A_CPU1_SA_DQS_DP<3>")
	)
	(segment
		(start 63.232792 -285.036768)
		(end 63.006224 -285.036768)
		(width 0.20066)
		(layer "F.Cu")
		(net "M_A_CPU1_SA_DQS_DP<3>")
	)
	(segment
		(start 63.900812 -285.309564)
		(end 63.505588 -285.309564)
		(width 0.20066)
		(layer "F.Cu")
		(net "M_A_CPU1_SA_DQS_DP<3>")
	)
	(segment
		(start 53.941218 -284.866588)
		(end 54.20233 -284.605476)
		(width 0.20066)
		(layer "F.Cu")
		(net "M_A_CPU1_SA_DQS_DP<3>")
	)
	(segment
		(start 66.1797 -285.298642)
		(end 66.172588 -285.29153)
		(width 0.1016)
		(layer "F.Cu")
		(net "M_A_CPU1_SA_DQS_DP<3>")
	)
	(segment
		(start 74.991214 -282.160218)
		(end 72.366378 -284.785054)
		(width 0.20066)
		(layer "F.Cu")
		(net "M_A_CPU1_SA_DQS_DP<3>")
	)
	(segment
		(start 66.561462 -285.298642)
		(end 66.186812 -285.298642)
		(width 0.20066)
		(layer "F.Cu")
		(net "M_A_CPU1_SA_DQS_DP<3>")
	)
	(segment
		(start 63.937896 -285.29153)
		(end 63.919862 -285.309564)
		(width 0.1016)
		(layer "F.Cu")
		(net "M_A_CPU1_SA_DQS_DP<3>")
	)
	(segment
		(start 54.20233 -284.605476)
		(end 54.666134 -284.605476)
		(width 0.20066)
		(layer "F.Cu")
		(net "M_A_CPU1_SA_DQS_DP<3>")
	)
	(segment
		(start 66.186812 -285.298642)
		(end 66.1797 -285.298642)
		(width 0.1016)
		(layer "F.Cu")
		(net "M_A_CPU1_SA_DQS_DP<3>")
	)
	(segment
		(start 66.613278 -285.246826)
		(end 66.561462 -285.298642)
		(width 0.20066)
		(layer "F.Cu")
		(net "M_A_CPU1_SA_DQS_DP<3>")
	)
	(segment
		(start 85.43671 -267.349986)
		(end 84.890102 -267.6779)
		(width 0.088646)
		(layer "F.Cu")
		(net "M_A_CPU1_SA_DQS_DP<3>")
	)
	(segment
		(start 56.388508 -285.291784)
		(end 58.69686 -285.291784)
		(width 0.1016)
		(layer "F.Cu")
		(net "M_A_CPU1_SA_DQS_DP<3>")
	)
	(segment
		(start 83.926426 -268.64183)
		(end 83.649058 -268.756892)
		(width 0.088646)
		(layer "F.Cu")
		(net "M_A_CPU1_SA_DQS_DP<3>")
	)
	(segment
		(start 75.018138 -282.080716)
		(end 75.018138 -282.133294)
		(width 0.1524)
		(layer "F.Cu")
		(net "M_A_CPU1_SA_DQS_DP<3>")
	)
	(segment
		(start 59.977274 -284.605476)
		(end 60.137294 -284.605476)
		(width 0.20066)
		(layer "F.Cu")
		(net "M_A_CPU1_SA_DQS_DP<3>")
	)
	(segment
		(start 83.1215 -269.33017)
		(end 83.106006 -269.345664)
		(width 0.088646)
		(layer "F.Cu")
		(net "M_A_CPU1_SA_DQS_DP<3>")
	)
	(segment
		(start 60.137294 -284.605476)
		(end 60.398406 -284.866588)
		(width 0.20066)
		(layer "F.Cu")
		(net "M_A_CPU1_SA_DQS_DP<3>")
	)
	(segment
		(start 55.30215 -285.030672)
		(end 55.69839 -285.030672)
		(width 0.20066)
		(layer "F.Cu")
		(net "M_A_CPU1_SA_DQS_DP<3>")
	)
	(segment
		(start 85.905594 -267.219938)
		(end 85.43671 -267.349986)
		(width 0.088646)
		(layer "F.Cu")
		(net "M_A_CPU1_SA_DQS_DP<3>")
	)
	(segment
		(start 53.403246 -284.866588)
		(end 53.941218 -284.866588)
		(width 0.20066)
		(layer "F.Cu")
		(net "M_A_CPU1_SA_DQS_DP<3>")
	)
	(segment
		(start 56.37911 -285.301182)
		(end 56.388508 -285.291784)
		(width 0.1016)
		(layer "F.Cu")
		(net "M_A_CPU1_SA_DQS_DP<3>")
	)
	(segment
		(start 75.345036 -281.753818)
		(end 75.018138 -282.080716)
		(width 0.1524)
		(layer "F.Cu")
		(net "M_A_CPU1_SA_DQS_DP<3>")
	)
	(segment
		(start 55.9689 -285.301182)
		(end 56.37911 -285.301182)
		(width 0.20066)
		(layer "F.Cu")
		(net "M_A_CPU1_SA_DQS_DP<3>")
	)
	(segment
		(start 83.649058 -268.756892)
		(end 83.1215 -269.28445)
		(width 0.088646)
		(layer "F.Cu")
		(net "M_A_CPU1_SA_DQS_DP<3>")
	)
	(segment
		(start 83.1215 -269.28445)
		(end 83.1215 -269.33017)
		(width 0.088646)
		(layer "F.Cu")
		(net "M_A_CPU1_SA_DQS_DP<3>")
	)
	(segment
		(start 59.160156 -285.030672)
		(end 59.552078 -285.030672)
		(width 0.20066)
		(layer "F.Cu")
		(net "M_A_CPU1_SA_DQS_DP<3>")
	)
	(segment
		(start 61.439806 -284.866588)
		(end 60.947046 -284.866588)
		(width 0.20066)
		(layer "F.Cu")
		(net "M_A_CPU1_SA_DQS_DP<3>")
	)
	(segment
		(start 55.69839 -285.030672)
		(end 55.9689 -285.301182)
		(width 0.20066)
		(layer "F.Cu")
		(net "M_A_CPU1_SA_DQS_DP<3>")
	)
	(segment
		(start 83.106006 -269.345664)
		(end 77.827632 -274.624038)
		(width 0.1524)
		(layer "F.Cu")
		(net "M_A_CPU1_SA_DQS_DP<3>")
	)
	(segment
		(start 76.576428 -276.964648)
		(end 75.930252 -280.213562)
		(width 0.1524)
		(layer "F.Cu")
		(net "M_A_CPU1_SA_DQS_DP<3>")
	)
	(segment
		(start 58.69686 -285.291784)
		(end 58.704226 -285.291784)
		(width 0.101854)
		(layer "F.Cu")
		(net "M_A_CPU1_SA_DQS_DP<3>")
	)
	(segment
		(start 61.691012 -284.615382)
		(end 61.439806 -284.866588)
		(width 0.20066)
		(layer "F.Cu")
		(net "M_A_CPU1_SA_DQS_DP<3>")
	)
	(segment
		(start 70.043802 -285.246826)
		(end 66.613278 -285.246826)
		(width 0.20066)
		(layer "F.Cu")
		(net "M_A_CPU1_SA_DQS_DP<3>")
	)
	(segment
		(start 63.505588 -285.309564)
		(end 63.232792 -285.036768)
		(width 0.20066)
		(layer "F.Cu")
		(net "M_A_CPU1_SA_DQS_DP<3>")
	)
	(segment
		(start 77.827632 -274.624038)
		(end 76.576428 -276.964648)
		(width 0.1524)
		(layer "F.Cu")
		(net "M_A_CPU1_SA_DQS_DP<3>")
	)
	(segment
		(start 58.704226 -285.291784)
		(end 58.899044 -285.291784)
		(width 0.20066)
		(layer "F.Cu")
		(net "M_A_CPU1_SA_DQS_DP<3>")
	)
	(segment
		(start 72.366378 -284.785054)
		(end 70.043802 -285.246826)
		(width 0.20066)
		(layer "F.Cu")
		(net "M_A_CPU1_SA_DQS_DP<3>")
	)
	(segment
		(start 75.018138 -282.133294)
		(end 74.991214 -282.160218)
		(width 0.1524)
		(layer "F.Cu")
		(net "M_A_CPU1_SA_DQS_DP<3>")
	)
	(segment
		(start 66.172588 -285.29153)
		(end 63.937896 -285.29153)
		(width 0.1016)
		(layer "F.Cu")
		(net "M_A_CPU1_SA_DQS_DP<3>")
	)
	(segment
		(start 63.006224 -285.036768)
		(end 61.988954 -284.615382)
		(width 0.20066)
		(layer "F.Cu")
		(net "M_A_CPU1_SA_DQS_DP<3>")
	)
	(segment
		(start 60.398406 -284.866588)
		(end 60.947046 -284.866588)
		(width 0.20066)
		(layer "F.Cu")
		(net "M_A_CPU1_SA_DQS_DP<3>")
	)
	(segment
		(start 54.666134 -284.605476)
		(end 55.30215 -285.030672)
		(width 0.20066)
		(layer "F.Cu")
		(net "M_A_CPU1_SA_DQS_DP<3>")
	)
	(segment
		(start 84.890102 -267.6779)
		(end 83.926426 -268.64183)
		(width 0.088646)
		(layer "F.Cu")
		(net "M_A_CPU1_SA_DQS_DP<3>")
	)
	(segment
		(start 61.988954 -284.615382)
		(end 61.691012 -284.615382)
		(width 0.20066)
		(layer "F.Cu")
		(net "M_A_CPU1_SA_DQS_DP<3>")
	)
	(segment
		(start 63.919862 -285.309564)
		(end 63.900812 -285.309564)
		(width 0.1016)
		(layer "F.Cu")
		(net "M_A_CPU1_SA_DQS_DP<3>")
	)
	(segment
		(start 75.930252 -280.213562)
		(end 75.345036 -281.753818)
		(width 0.1524)
		(layer "F.Cu")
		(net "M_A_CPU1_SA_DQS_DP<3>")
	)
	(segment
		(start 84.408518 -273.385026)
		(end 84.006182 -273.986498)
		(width 0.088646)
		(layer "F.Cu")
		(net "M_A_CPU1_SA_DQS_DP<2>")
	)
	(segment
		(start 59.977274 -293.95547)
		(end 60.137294 -293.95547)
		(width 0.20066)
		(layer "F.Cu")
		(net "M_A_CPU1_SA_DQS_DP<2>")
	)
	(segment
		(start 59.302396 -294.380666)
		(end 59.552078 -294.380666)
		(width 0.20066)
		(layer "F.Cu")
		(net "M_A_CPU1_SA_DQS_DP<2>")
	)
	(segment
		(start 79.686912 -281.65679)
		(end 79.686912 -290.942776)
		(width 0.1524)
		(layer "F.Cu")
		(net "M_A_CPU1_SA_DQS_DP<2>")
	)
	(segment
		(start 55.30215 -294.380666)
		(end 55.69839 -294.380666)
		(width 0.20066)
		(layer "F.Cu")
		(net "M_A_CPU1_SA_DQS_DP<2>")
	)
	(segment
		(start 79.446882 -291.182806)
		(end 79.446882 -291.235384)
		(width 0.1524)
		(layer "F.Cu")
		(net "M_A_CPU1_SA_DQS_DP<2>")
	)
	(segment
		(start 80.988154 -277.097998)
		(end 80.3656 -278.26335)
		(width 0.1524)
		(layer "F.Cu")
		(net "M_A_CPU1_SA_DQS_DP<2>")
	)
	(segment
		(start 83.624674 -274.461478)
		(end 80.988154 -277.097998)
		(width 0.1524)
		(layer "F.Cu")
		(net "M_A_CPU1_SA_DQS_DP<2>")
	)
	(segment
		(start 54.666134 -293.95547)
		(end 55.30215 -294.380666)
		(width 0.20066)
		(layer "F.Cu")
		(net "M_A_CPU1_SA_DQS_DP<2>")
	)
	(segment
		(start 55.9689 -294.651176)
		(end 56.37911 -294.651176)
		(width 0.20066)
		(layer "F.Cu")
		(net "M_A_CPU1_SA_DQS_DP<2>")
	)
	(segment
		(start 84.71027 -273.187414)
		(end 84.620862 -273.224498)
		(width 0.088646)
		(layer "F.Cu")
		(net "M_A_CPU1_SA_DQS_DP<2>")
	)
	(segment
		(start 61.877448 -293.945056)
		(end 61.711332 -293.945056)
		(width 0.20066)
		(layer "F.Cu")
		(net "M_A_CPU1_SA_DQS_DP<2>")
	)
	(segment
		(start 63.498984 -294.444674)
		(end 63.083694 -294.444674)
		(width 0.20066)
		(layer "F.Cu")
		(net "M_A_CPU1_SA_DQS_DP<2>")
	)
	(segment
		(start 61.711332 -293.945056)
		(end 61.439806 -294.216582)
		(width 0.20066)
		(layer "F.Cu")
		(net "M_A_CPU1_SA_DQS_DP<2>")
	)
	(segment
		(start 83.640168 -274.400264)
		(end 83.640168 -274.445984)
		(width 0.088646)
		(layer "F.Cu")
		(net "M_A_CPU1_SA_DQS_DP<2>")
	)
	(segment
		(start 59.033918 -294.649144)
		(end 59.302396 -294.380666)
		(width 0.20066)
		(layer "F.Cu")
		(net "M_A_CPU1_SA_DQS_DP<2>")
	)
	(segment
		(start 56.37911 -294.651176)
		(end 56.388508 -294.641778)
		(width 0.1016)
		(layer "F.Cu")
		(net "M_A_CPU1_SA_DQS_DP<2>")
	)
	(segment
		(start 85.823044 -272.302732)
		(end 85.823044 -272.798032)
		(width 0.088646)
		(layer "F.Cu")
		(net "M_A_CPU1_SA_DQS_DP<2>")
	)
	(segment
		(start 53.403246 -294.216582)
		(end 53.941218 -294.216582)
		(width 0.20066)
		(layer "F.Cu")
		(net "M_A_CPU1_SA_DQS_DP<2>")
	)
	(segment
		(start 79.686912 -290.942776)
		(end 79.446882 -291.182806)
		(width 0.1524)
		(layer "F.Cu")
		(net "M_A_CPU1_SA_DQS_DP<2>")
	)
	(segment
		(start 54.20233 -293.95547)
		(end 54.666134 -293.95547)
		(width 0.20066)
		(layer "F.Cu")
		(net "M_A_CPU1_SA_DQS_DP<2>")
	)
	(segment
		(start 84.620862 -273.224498)
		(end 84.531708 -273.261328)
		(width 0.088646)
		(layer "F.Cu")
		(net "M_A_CPU1_SA_DQS_DP<2>")
	)
	(segment
		(start 77.056996 -293.62527)
		(end 74.603102 -294.641524)
		(width 0.20066)
		(layer "F.Cu")
		(net "M_A_CPU1_SA_DQS_DP<2>")
	)
	(segment
		(start 60.398406 -294.216582)
		(end 60.947046 -294.216582)
		(width 0.20066)
		(layer "F.Cu")
		(net "M_A_CPU1_SA_DQS_DP<2>")
	)
	(segment
		(start 56.388508 -294.641778)
		(end 58.69686 -294.641778)
		(width 0.1016)
		(layer "F.Cu")
		(net "M_A_CPU1_SA_DQS_DP<2>")
	)
	(segment
		(start 59.552078 -294.380666)
		(end 59.977274 -293.95547)
		(width 0.20066)
		(layer "F.Cu")
		(net "M_A_CPU1_SA_DQS_DP<2>")
	)
	(segment
		(start 83.640168 -274.445984)
		(end 83.624674 -274.461478)
		(width 0.088646)
		(layer "F.Cu")
		(net "M_A_CPU1_SA_DQS_DP<2>")
	)
	(segment
		(start 84.97443 -273.187414)
		(end 84.71027 -273.187414)
		(width 0.088646)
		(layer "F.Cu")
		(net "M_A_CPU1_SA_DQS_DP<2>")
	)
	(segment
		(start 53.941218 -294.216582)
		(end 54.20233 -293.95547)
		(width 0.20066)
		(layer "F.Cu")
		(net "M_A_CPU1_SA_DQS_DP<2>")
	)
	(segment
		(start 66.237612 -294.641524)
		(end 64.157606 -294.641524)
		(width 0.1016)
		(layer "F.Cu")
		(net "M_A_CPU1_SA_DQS_DP<2>")
	)
	(segment
		(start 58.69686 -294.641778)
		(end 58.704226 -294.649144)
		(width 0.1016)
		(layer "F.Cu")
		(net "M_A_CPU1_SA_DQS_DP<2>")
	)
	(segment
		(start 58.704226 -294.649144)
		(end 59.033918 -294.649144)
		(width 0.20066)
		(layer "F.Cu")
		(net "M_A_CPU1_SA_DQS_DP<2>")
	)
	(segment
		(start 80.3656 -278.26335)
		(end 79.686912 -281.65679)
		(width 0.1524)
		(layer "F.Cu")
		(net "M_A_CPU1_SA_DQS_DP<2>")
	)
	(segment
		(start 84.97824 -273.189192)
		(end 84.97443 -273.187414)
		(width 0.088646)
		(layer "F.Cu")
		(net "M_A_CPU1_SA_DQS_DP<2>")
	)
	(segment
		(start 84.006182 -273.986498)
		(end 83.787234 -274.253198)
		(width 0.088646)
		(layer "F.Cu")
		(net "M_A_CPU1_SA_DQS_DP<2>")
	)
	(segment
		(start 85.137498 -273.254978)
		(end 84.97824 -273.189192)
		(width 0.088646)
		(layer "F.Cu")
		(net "M_A_CPU1_SA_DQS_DP<2>")
	)
	(segment
		(start 60.137294 -293.95547)
		(end 60.398406 -294.216582)
		(width 0.20066)
		(layer "F.Cu")
		(net "M_A_CPU1_SA_DQS_DP<2>")
	)
	(segment
		(start 63.900812 -294.678608)
		(end 63.732918 -294.678608)
		(width 0.20066)
		(layer "F.Cu")
		(net "M_A_CPU1_SA_DQS_DP<2>")
	)
	(segment
		(start 84.531708 -273.261328)
		(end 84.408518 -273.385026)
		(width 0.088646)
		(layer "F.Cu")
		(net "M_A_CPU1_SA_DQS_DP<2>")
	)
	(segment
		(start 74.603102 -294.641524)
		(end 66.237612 -294.641524)
		(width 0.20066)
		(layer "F.Cu")
		(net "M_A_CPU1_SA_DQS_DP<2>")
	)
	(segment
		(start 63.732918 -294.678608)
		(end 63.498984 -294.444674)
		(width 0.20066)
		(layer "F.Cu")
		(net "M_A_CPU1_SA_DQS_DP<2>")
	)
	(segment
		(start 64.157606 -294.641524)
		(end 63.983108 -294.678608)
		(width 0.1016)
		(layer "F.Cu")
		(net "M_A_CPU1_SA_DQS_DP<2>")
	)
	(segment
		(start 63.083694 -294.444674)
		(end 61.877448 -293.945056)
		(width 0.20066)
		(layer "F.Cu")
		(net "M_A_CPU1_SA_DQS_DP<2>")
	)
	(segment
		(start 79.446882 -291.235384)
		(end 79.419958 -291.262308)
		(width 0.1524)
		(layer "F.Cu")
		(net "M_A_CPU1_SA_DQS_DP<2>")
	)
	(segment
		(start 55.69839 -294.380666)
		(end 55.9689 -294.651176)
		(width 0.20066)
		(layer "F.Cu")
		(net "M_A_CPU1_SA_DQS_DP<2>")
	)
	(segment
		(start 85.461602 -273.254978)
		(end 85.137498 -273.254978)
		(width 0.088646)
		(layer "F.Cu")
		(net "M_A_CPU1_SA_DQS_DP<2>")
	)
	(segment
		(start 61.439806 -294.216582)
		(end 60.947046 -294.216582)
		(width 0.20066)
		(layer "F.Cu")
		(net "M_A_CPU1_SA_DQS_DP<2>")
	)
	(segment
		(start 63.983108 -294.678608)
		(end 63.900812 -294.678608)
		(width 0.1016)
		(layer "F.Cu")
		(net "M_A_CPU1_SA_DQS_DP<2>")
	)
	(segment
		(start 85.905594 -272.103342)
		(end 85.823044 -272.302732)
		(width 0.088646)
		(layer "F.Cu")
		(net "M_A_CPU1_SA_DQS_DP<2>")
	)
	(segment
		(start 83.787234 -274.253198)
		(end 83.640168 -274.400264)
		(width 0.088646)
		(layer "F.Cu")
		(net "M_A_CPU1_SA_DQS_DP<2>")
	)
	(segment
		(start 79.419958 -291.262308)
		(end 77.056996 -293.62527)
		(width 0.20066)
		(layer "F.Cu")
		(net "M_A_CPU1_SA_DQS_DP<2>")
	)
	(arc
		(start 85.823044 -272.798032)
		(mid 85.784998 -272.9953)
		(end 85.675978 -273.164046)
		(width 0.088646)
		(layer "F.Cu")
		(net "M_A_CPU1_SA_DQS_DP<2>")
	)
	(arc
		(start 85.675978 -273.164046)
		(mid 85.578047 -273.231355)
		(end 85.461602 -273.254978)
		(width 0.088646)
		(layer "F.Cu")
		(net "M_A_CPU1_SA_DQS_DP<2>")
	)
	(segment
		(start 56.37911 -304.00117)
		(end 56.160924 -304.00117)
		(width 0.20066)
		(layer "F.Cu")
		(net "M_A_CPU1_SA_DQS_DP<1>")
	)
	(segment
		(start 54.627272 -303.305464)
		(end 54.20233 -303.305464)
		(width 0.20066)
		(layer "F.Cu")
		(net "M_A_CPU1_SA_DQS_DP<1>")
	)
	(segment
		(start 54.20233 -303.305464)
		(end 53.941218 -303.566576)
		(width 0.20066)
		(layer "F.Cu")
		(net "M_A_CPU1_SA_DQS_DP<1>")
	)
	(segment
		(start 62.051946 -303.566576)
		(end 60.947046 -303.566576)
		(width 0.20066)
		(layer "F.Cu")
		(net "M_A_CPU1_SA_DQS_DP<1>")
	)
	(segment
		(start 60.137294 -303.305464)
		(end 59.868562 -303.305464)
		(width 0.20066)
		(layer "F.Cu")
		(net "M_A_CPU1_SA_DQS_DP<1>")
	)
	(segment
		(start 55.263288 -303.73066)
		(end 54.627272 -303.305464)
		(width 0.20066)
		(layer "F.Cu")
		(net "M_A_CPU1_SA_DQS_DP<1>")
	)
	(segment
		(start 56.388508 -303.991772)
		(end 56.37911 -304.00117)
		(width 0.101854)
		(layer "F.Cu")
		(net "M_A_CPU1_SA_DQS_DP<1>")
	)
	(segment
		(start 56.160924 -304.00117)
		(end 55.890414 -303.73066)
		(width 0.20066)
		(layer "F.Cu")
		(net "M_A_CPU1_SA_DQS_DP<1>")
	)
	(segment
		(start 59.117484 -303.73066)
		(end 58.856372 -303.991772)
		(width 0.20066)
		(layer "F.Cu")
		(net "M_A_CPU1_SA_DQS_DP<1>")
	)
	(segment
		(start 58.704226 -303.991772)
		(end 58.380884 -303.991772)
		(width 0.101854)
		(layer "F.Cu")
		(net "M_A_CPU1_SA_DQS_DP<1>")
	)
	(segment
		(start 59.443366 -303.73066)
		(end 59.117484 -303.73066)
		(width 0.20066)
		(layer "F.Cu")
		(net "M_A_CPU1_SA_DQS_DP<1>")
	)
	(segment
		(start 89.194894 -269.66164)
		(end 89.194894 -270.19758)
		(width 0.20066)
		(layer "F.Cu")
		(net "M_A_CPU1_SA_DQS_DP<1>")
	)
	(segment
		(start 56.62549 -303.991772)
		(end 56.388508 -303.991772)
		(width 0.101854)
		(layer "F.Cu")
		(net "M_A_CPU1_SA_DQS_DP<1>")
	)
	(segment
		(start 58.856372 -303.991772)
		(end 58.704226 -303.991772)
		(width 0.20066)
		(layer "F.Cu")
		(net "M_A_CPU1_SA_DQS_DP<1>")
	)
	(segment
		(start 55.890414 -303.73066)
		(end 55.263288 -303.73066)
		(width 0.20066)
		(layer "F.Cu")
		(net "M_A_CPU1_SA_DQS_DP<1>")
	)
	(segment
		(start 53.941218 -303.566576)
		(end 53.403246 -303.566576)
		(width 0.20066)
		(layer "F.Cu")
		(net "M_A_CPU1_SA_DQS_DP<1>")
	)
	(segment
		(start 60.947046 -303.566576)
		(end 60.398406 -303.566576)
		(width 0.20066)
		(layer "F.Cu")
		(net "M_A_CPU1_SA_DQS_DP<1>")
	)
	(segment
		(start 60.398406 -303.566576)
		(end 60.137294 -303.305464)
		(width 0.20066)
		(layer "F.Cu")
		(net "M_A_CPU1_SA_DQS_DP<1>")
	)
	(segment
		(start 59.868562 -303.305464)
		(end 59.443366 -303.73066)
		(width 0.20066)
		(layer "F.Cu")
		(net "M_A_CPU1_SA_DQS_DP<1>")
	)
	(segment
		(start 58.380884 -303.991772)
		(end 56.62549 -303.991772)
		(width 0.1016)
		(layer "F.Cu")
		(net "M_A_CPU1_SA_DQS_DP<1>")
	)
	(segment
		(start 88.853264 -270.288004)
		(end 88.429338 -270.52905)
		(width 0.088646)
		(layer "In2.Cu")
		(net "M_A_CPU1_SA_DQS_DP<1>")
	)
	(segment
		(start 82.74812 -273.722084)
		(end 81.474564 -276.800564)
		(width 0.18288)
		(layer "In2.Cu")
		(net "M_A_CPU1_SA_DQS_DP<1>")
	)
	(segment
		(start 65.680336 -303.70526)
		(end 64.64554 -303.70526)
		(width 0.18288)
		(layer "In2.Cu")
		(net "M_A_CPU1_SA_DQS_DP<1>")
	)
	(segment
		(start 64.64554 -303.70526)
		(end 64.368426 -303.590452)
		(width 0.18288)
		(layer "In2.Cu")
		(net "M_A_CPU1_SA_DQS_DP<1>")
	)
	(segment
		(start 76.346558 -283.531564)
		(end 73.66 -286.218122)
		(width 0.18288)
		(layer "In2.Cu")
		(net "M_A_CPU1_SA_DQS_DP<1>")
	)
	(segment
		(start 77.40142 -280.986484)
		(end 76.346558 -283.531564)
		(width 0.18288)
		(layer "In2.Cu")
		(net "M_A_CPU1_SA_DQS_DP<1>")
	)
	(segment
		(start 86.580218 -270.74622)
		(end 86.156038 -271.1704)
		(width 0.088646)
		(layer "In2.Cu")
		(net "M_A_CPU1_SA_DQS_DP<1>")
	)
	(segment
		(start 85.10397 -271.281398)
		(end 85.10397 -271.365726)
		(width 0.088646)
		(layer "In2.Cu")
		(net "M_A_CPU1_SA_DQS_DP<1>")
	)
	(segment
		(start 62.711076 -303.314354)
		(end 62.304168 -303.314354)
		(width 0.18288)
		(layer "In2.Cu")
		(net "M_A_CPU1_SA_DQS_DP<1>")
	)
	(segment
		(start 85.10397 -271.365726)
		(end 84.84362 -271.626076)
		(width 0.18288)
		(layer "In2.Cu")
		(net "M_A_CPU1_SA_DQS_DP<1>")
	)
	(segment
		(start 68.928234 -300.362874)
		(end 67.977766 -302.65751)
		(width 0.18288)
		(layer "In2.Cu")
		(net "M_A_CPU1_SA_DQS_DP<1>")
	)
	(segment
		(start 66.609976 -303.719738)
		(end 66.338196 -303.991518)
		(width 0.18288)
		(layer "In2.Cu")
		(net "M_A_CPU1_SA_DQS_DP<1>")
	)
	(segment
		(start 68.928234 -297.632374)
		(end 68.928234 -300.362874)
		(width 0.18288)
		(layer "In2.Cu")
		(net "M_A_CPU1_SA_DQS_DP<1>")
	)
	(segment
		(start 86.156038 -271.1704)
		(end 85.214968 -271.1704)
		(width 0.088646)
		(layer "In2.Cu")
		(net "M_A_CPU1_SA_DQS_DP<1>")
	)
	(segment
		(start 63.07836 -302.94707)
		(end 62.711076 -303.314354)
		(width 0.18288)
		(layer "In2.Cu")
		(net "M_A_CPU1_SA_DQS_DP<1>")
	)
	(segment
		(start 89.194894 -270.19758)
		(end 88.853264 -270.288004)
		(width 0.088646)
		(layer "In2.Cu")
		(net "M_A_CPU1_SA_DQS_DP<1>")
	)
	(segment
		(start 77.481176 -280.793952)
		(end 77.40142 -280.986484)
		(width 0.18288)
		(layer "In2.Cu")
		(net "M_A_CPU1_SA_DQS_DP<1>")
	)
	(segment
		(start 73.66 -286.218122)
		(end 68.928234 -297.632374)
		(width 0.18288)
		(layer "In2.Cu")
		(net "M_A_CPU1_SA_DQS_DP<1>")
	)
	(segment
		(start 63.91402 -303.136046)
		(end 63.885826 -303.107852)
		(width 0.16002)
		(layer "In2.Cu")
		(net "M_A_CPU1_SA_DQS_DP<1>")
	)
	(segment
		(start 63.725044 -302.94707)
		(end 63.07836 -302.94707)
		(width 0.18288)
		(layer "In2.Cu")
		(net "M_A_CPU1_SA_DQS_DP<1>")
	)
	(segment
		(start 66.915538 -303.719738)
		(end 66.609976 -303.719738)
		(width 0.18288)
		(layer "In2.Cu")
		(net "M_A_CPU1_SA_DQS_DP<1>")
	)
	(segment
		(start 64.12992 -303.336198)
		(end 63.929768 -303.136046)
		(width 0.16002)
		(layer "In2.Cu")
		(net "M_A_CPU1_SA_DQS_DP<1>")
	)
	(segment
		(start 85.214968 -271.1704)
		(end 85.10397 -271.281398)
		(width 0.088646)
		(layer "In2.Cu")
		(net "M_A_CPU1_SA_DQS_DP<1>")
	)
	(segment
		(start 63.885826 -303.107852)
		(end 63.725044 -302.94707)
		(width 0.18288)
		(layer "In2.Cu")
		(net "M_A_CPU1_SA_DQS_DP<1>")
	)
	(segment
		(start 67.977766 -302.65751)
		(end 66.915538 -303.719738)
		(width 0.18288)
		(layer "In2.Cu")
		(net "M_A_CPU1_SA_DQS_DP<1>")
	)
	(segment
		(start 88.191848 -270.603726)
		(end 87.742268 -270.603726)
		(width 0.088646)
		(layer "In2.Cu")
		(net "M_A_CPU1_SA_DQS_DP<1>")
	)
	(segment
		(start 87.742268 -270.603726)
		(end 87.597996 -270.687038)
		(width 0.088646)
		(layer "In2.Cu")
		(net "M_A_CPU1_SA_DQS_DP<1>")
	)
	(segment
		(start 65.966594 -303.991518)
		(end 65.680336 -303.70526)
		(width 0.18288)
		(layer "In2.Cu")
		(net "M_A_CPU1_SA_DQS_DP<1>")
	)
	(segment
		(start 64.368426 -303.590452)
		(end 64.158114 -303.38014)
		(width 0.18288)
		(layer "In2.Cu")
		(net "M_A_CPU1_SA_DQS_DP<1>")
	)
	(segment
		(start 88.224868 -270.570706)
		(end 88.191848 -270.603726)
		(width 0.088646)
		(layer "In2.Cu")
		(net "M_A_CPU1_SA_DQS_DP<1>")
	)
	(segment
		(start 62.304168 -303.314354)
		(end 62.051946 -303.566576)
		(width 0.18288)
		(layer "In2.Cu")
		(net "M_A_CPU1_SA_DQS_DP<1>")
	)
	(segment
		(start 64.158114 -303.38014)
		(end 64.12992 -303.351946)
		(width 0.16002)
		(layer "In2.Cu")
		(net "M_A_CPU1_SA_DQS_DP<1>")
	)
	(segment
		(start 64.12992 -303.351946)
		(end 64.12992 -303.336198)
		(width 0.16002)
		(layer "In2.Cu")
		(net "M_A_CPU1_SA_DQS_DP<1>")
	)
	(segment
		(start 81.474564 -276.800564)
		(end 77.481176 -280.793952)
		(width 0.18288)
		(layer "In2.Cu")
		(net "M_A_CPU1_SA_DQS_DP<1>")
	)
	(segment
		(start 84.84362 -271.626076)
		(end 82.74812 -273.722084)
		(width 0.18288)
		(layer "In2.Cu")
		(net "M_A_CPU1_SA_DQS_DP<1>")
	)
	(segment
		(start 66.338196 -303.991518)
		(end 65.966594 -303.991518)
		(width 0.18288)
		(layer "In2.Cu")
		(net "M_A_CPU1_SA_DQS_DP<1>")
	)
	(segment
		(start 63.929768 -303.136046)
		(end 63.91402 -303.136046)
		(width 0.16002)
		(layer "In2.Cu")
		(net "M_A_CPU1_SA_DQS_DP<1>")
	)
	(arc
		(start 87.032592 -270.687038)
		(mid 86.845394 -270.636895)
		(end 86.658196 -270.687038)
		(width 0.088646)
		(layer "In2.Cu")
		(net "M_A_CPU1_SA_DQS_DP<1>")
	)
	(arc
		(start 87.597996 -270.687038)
		(mid 87.315294 -270.762814)
		(end 87.032592 -270.687038)
		(width 0.088646)
		(layer "In2.Cu")
		(net "M_A_CPU1_SA_DQS_DP<1>")
	)
	(arc
		(start 88.429338 -270.52905)
		(mid 88.330496 -270.56656)
		(end 88.224868 -270.570706)
		(width 0.088646)
		(layer "In2.Cu")
		(net "M_A_CPU1_SA_DQS_DP<1>")
	)
	(arc
		(start 86.658196 -270.687038)
		(mid 86.617266 -270.714071)
		(end 86.580218 -270.74622)
		(width 0.088646)
		(layer "In2.Cu")
		(net "M_A_CPU1_SA_DQS_DP<1>")
	)
	(segment
		(start 85.997034 -277.868126)
		(end 86.064598 -277.800562)
		(width 0.088646)
		(layer "F.Cu")
		(net "M_A_CPU1_SA_DQS_DP<0>")
	)
	(segment
		(start 66.161412 -313.3471)
		(end 66.58991 -313.3471)
		(width 0.20066)
		(layer "F.Cu")
		(net "M_A_CPU1_SA_DQS_DP<0>")
	)
	(segment
		(start 84.996274 -278.32812)
		(end 85.558122 -278.32812)
		(width 0.088646)
		(layer "F.Cu")
		(net "M_A_CPU1_SA_DQS_DP<0>")
	)
	(segment
		(start 84.801202 -278.902922)
		(end 84.801202 -278.632666)
		(width 0.088646)
		(layer "F.Cu")
		(net "M_A_CPU1_SA_DQS_DP<0>")
	)
	(segment
		(start 59.552078 -313.080654)
		(end 59.977274 -312.655458)
		(width 0.20066)
		(layer "F.Cu")
		(net "M_A_CPU1_SA_DQS_DP<0>")
	)
	(segment
		(start 54.671468 -312.655458)
		(end 55.307484 -313.080654)
		(width 0.20066)
		(layer "F.Cu")
		(net "M_A_CPU1_SA_DQS_DP<0>")
	)
	(segment
		(start 67.109086 -313.060334)
		(end 67.380358 -312.948066)
		(width 0.20066)
		(layer "F.Cu")
		(net "M_A_CPU1_SA_DQS_DP<0>")
	)
	(segment
		(start 60.947046 -312.91657)
		(end 61.439806 -312.91657)
		(width 0.20066)
		(layer "F.Cu")
		(net "M_A_CPU1_SA_DQS_DP<0>")
	)
	(segment
		(start 59.033918 -313.349132)
		(end 59.302396 -313.080654)
		(width 0.20066)
		(layer "F.Cu")
		(net "M_A_CPU1_SA_DQS_DP<0>")
	)
	(segment
		(start 66.58991 -313.3471)
		(end 66.876676 -313.060334)
		(width 0.20066)
		(layer "F.Cu")
		(net "M_A_CPU1_SA_DQS_DP<0>")
	)
	(segment
		(start 61.691012 -312.665364)
		(end 61.917072 -312.665364)
		(width 0.20066)
		(layer "F.Cu")
		(net "M_A_CPU1_SA_DQS_DP<0>")
	)
	(segment
		(start 59.977274 -312.655458)
		(end 60.137294 -312.655458)
		(width 0.20066)
		(layer "F.Cu")
		(net "M_A_CPU1_SA_DQS_DP<0>")
	)
	(segment
		(start 56.37911 -313.351164)
		(end 56.388508 -313.341766)
		(width 0.1016)
		(layer "F.Cu")
		(net "M_A_CPU1_SA_DQS_DP<0>")
	)
	(segment
		(start 84.398104 -279.476454)
		(end 84.67979 -279.194768)
		(width 0.088646)
		(layer "F.Cu")
		(net "M_A_CPU1_SA_DQS_DP<0>")
	)
	(segment
		(start 84.67979 -279.194768)
		(end 84.801202 -278.902922)
		(width 0.088646)
		(layer "F.Cu")
		(net "M_A_CPU1_SA_DQS_DP<0>")
	)
	(segment
		(start 84.38261 -279.53716)
		(end 84.398104 -279.521666)
		(width 0.088646)
		(layer "F.Cu")
		(net "M_A_CPU1_SA_DQS_DP<0>")
	)
	(segment
		(start 53.403246 -312.91657)
		(end 53.941218 -312.91657)
		(width 0.20066)
		(layer "F.Cu")
		(net "M_A_CPU1_SA_DQS_DP<0>")
	)
	(segment
		(start 67.380358 -312.948066)
		(end 72.450706 -307.877972)
		(width 0.20066)
		(layer "F.Cu")
		(net "M_A_CPU1_SA_DQS_DP<0>")
	)
	(segment
		(start 58.69686 -313.341766)
		(end 58.704226 -313.349132)
		(width 0.1016)
		(layer "F.Cu")
		(net "M_A_CPU1_SA_DQS_DP<0>")
	)
	(segment
		(start 63.254636 -313.090306)
		(end 63.456312 -313.291982)
		(width 0.20066)
		(layer "F.Cu")
		(net "M_A_CPU1_SA_DQS_DP<0>")
	)
	(segment
		(start 55.9689 -313.351164)
		(end 56.37911 -313.351164)
		(width 0.20066)
		(layer "F.Cu")
		(net "M_A_CPU1_SA_DQS_DP<0>")
	)
	(segment
		(start 84.87791 -278.446484)
		(end 84.996274 -278.32812)
		(width 0.088646)
		(layer "F.Cu")
		(net "M_A_CPU1_SA_DQS_DP<0>")
	)
	(segment
		(start 62.942978 -313.090306)
		(end 63.254636 -313.090306)
		(width 0.20066)
		(layer "F.Cu")
		(net "M_A_CPU1_SA_DQS_DP<0>")
	)
	(segment
		(start 66.876676 -313.060334)
		(end 67.109086 -313.060334)
		(width 0.20066)
		(layer "F.Cu")
		(net "M_A_CPU1_SA_DQS_DP<0>")
	)
	(segment
		(start 72.450706 -307.877972)
		(end 76.697586 -304.39233)
		(width 0.20066)
		(layer "F.Cu")
		(net "M_A_CPU1_SA_DQS_DP<0>")
	)
	(segment
		(start 60.137294 -312.655458)
		(end 60.398406 -312.91657)
		(width 0.20066)
		(layer "F.Cu")
		(net "M_A_CPU1_SA_DQS_DP<0>")
	)
	(segment
		(start 61.917072 -312.665364)
		(end 62.942978 -313.090306)
		(width 0.20066)
		(layer "F.Cu")
		(net "M_A_CPU1_SA_DQS_DP<0>")
	)
	(segment
		(start 76.697586 -304.39233)
		(end 82.74431 -298.345606)
		(width 0.20066)
		(layer "F.Cu")
		(net "M_A_CPU1_SA_DQS_DP<0>")
	)
	(segment
		(start 83.131914 -297.905678)
		(end 83.374484 -297.312334)
		(width 0.1524)
		(layer "F.Cu")
		(net "M_A_CPU1_SA_DQS_DP<0>")
	)
	(segment
		(start 86.064598 -277.800562)
		(end 86.375494 -277.800562)
		(width 0.088646)
		(layer "F.Cu")
		(net "M_A_CPU1_SA_DQS_DP<0>")
	)
	(segment
		(start 59.302396 -313.080654)
		(end 59.552078 -313.080654)
		(width 0.20066)
		(layer "F.Cu")
		(net "M_A_CPU1_SA_DQS_DP<0>")
	)
	(segment
		(start 83.374484 -297.312334)
		(end 83.598512 -296.185082)
		(width 0.1524)
		(layer "F.Cu")
		(net "M_A_CPU1_SA_DQS_DP<0>")
	)
	(segment
		(start 66.142616 -313.341512)
		(end 66.148204 -313.3471)
		(width 0.1016)
		(layer "F.Cu")
		(net "M_A_CPU1_SA_DQS_DP<0>")
	)
	(segment
		(start 64.002412 -313.356244)
		(end 64.041528 -313.356244)
		(width 0.1016)
		(layer "F.Cu")
		(net "M_A_CPU1_SA_DQS_DP<0>")
	)
	(segment
		(start 84.801202 -278.632666)
		(end 84.87791 -278.446484)
		(width 0.088646)
		(layer "F.Cu")
		(net "M_A_CPU1_SA_DQS_DP<0>")
	)
	(segment
		(start 84.398104 -279.521666)
		(end 84.398104 -279.476454)
		(width 0.088646)
		(layer "F.Cu")
		(net "M_A_CPU1_SA_DQS_DP<0>")
	)
	(segment
		(start 64.041528 -313.356244)
		(end 64.05626 -313.341512)
		(width 0.1016)
		(layer "F.Cu")
		(net "M_A_CPU1_SA_DQS_DP<0>")
	)
	(segment
		(start 83.598512 -296.185082)
		(end 83.598512 -282.419298)
		(width 0.1524)
		(layer "F.Cu")
		(net "M_A_CPU1_SA_DQS_DP<0>")
	)
	(segment
		(start 82.771234 -298.266358)
		(end 83.131914 -297.905678)
		(width 0.1524)
		(layer "F.Cu")
		(net "M_A_CPU1_SA_DQS_DP<0>")
	)
	(segment
		(start 60.398406 -312.91657)
		(end 60.947046 -312.91657)
		(width 0.20066)
		(layer "F.Cu")
		(net "M_A_CPU1_SA_DQS_DP<0>")
	)
	(segment
		(start 82.771234 -298.318682)
		(end 82.771234 -298.266358)
		(width 0.1524)
		(layer "F.Cu")
		(net "M_A_CPU1_SA_DQS_DP<0>")
	)
	(segment
		(start 83.598512 -282.419298)
		(end 84.123276 -279.796494)
		(width 0.1524)
		(layer "F.Cu")
		(net "M_A_CPU1_SA_DQS_DP<0>")
	)
	(segment
		(start 66.148204 -313.3471)
		(end 66.161412 -313.3471)
		(width 0.1016)
		(layer "F.Cu")
		(net "M_A_CPU1_SA_DQS_DP<0>")
	)
	(segment
		(start 53.941218 -312.91657)
		(end 54.20233 -312.655458)
		(width 0.20066)
		(layer "F.Cu")
		(net "M_A_CPU1_SA_DQS_DP<0>")
	)
	(segment
		(start 82.74431 -298.345606)
		(end 82.771234 -298.318682)
		(width 0.1524)
		(layer "F.Cu")
		(net "M_A_CPU1_SA_DQS_DP<0>")
	)
	(segment
		(start 58.704226 -313.349132)
		(end 59.033918 -313.349132)
		(width 0.20066)
		(layer "F.Cu")
		(net "M_A_CPU1_SA_DQS_DP<0>")
	)
	(segment
		(start 61.439806 -312.91657)
		(end 61.691012 -312.665364)
		(width 0.20066)
		(layer "F.Cu")
		(net "M_A_CPU1_SA_DQS_DP<0>")
	)
	(segment
		(start 84.123276 -279.796494)
		(end 84.38261 -279.53716)
		(width 0.1524)
		(layer "F.Cu")
		(net "M_A_CPU1_SA_DQS_DP<0>")
	)
	(segment
		(start 63.456312 -313.291982)
		(end 63.611252 -313.356244)
		(width 0.20066)
		(layer "F.Cu")
		(net "M_A_CPU1_SA_DQS_DP<0>")
	)
	(segment
		(start 63.611252 -313.356244)
		(end 64.002412 -313.356244)
		(width 0.20066)
		(layer "F.Cu")
		(net "M_A_CPU1_SA_DQS_DP<0>")
	)
	(segment
		(start 64.05626 -313.341512)
		(end 66.142616 -313.341512)
		(width 0.1016)
		(layer "F.Cu")
		(net "M_A_CPU1_SA_DQS_DP<0>")
	)
	(segment
		(start 56.388508 -313.341766)
		(end 58.69686 -313.341766)
		(width 0.1016)
		(layer "F.Cu")
		(net "M_A_CPU1_SA_DQS_DP<0>")
	)
	(segment
		(start 55.69839 -313.080654)
		(end 55.9689 -313.351164)
		(width 0.20066)
		(layer "F.Cu")
		(net "M_A_CPU1_SA_DQS_DP<0>")
	)
	(segment
		(start 54.20233 -312.655458)
		(end 54.671468 -312.655458)
		(width 0.20066)
		(layer "F.Cu")
		(net "M_A_CPU1_SA_DQS_DP<0>")
	)
	(segment
		(start 55.307484 -313.080654)
		(end 55.69839 -313.080654)
		(width 0.20066)
		(layer "F.Cu")
		(net "M_A_CPU1_SA_DQS_DP<0>")
	)
	(arc
		(start 85.74913 -278.270462)
		(mid 85.911315 -278.105793)
		(end 85.993986 -277.88997)
		(width 0.088646)
		(layer "F.Cu")
		(net "M_A_CPU1_SA_DQS_DP<0>")
	)
	(arc
		(start 85.558122 -278.32812)
		(mid 85.657895 -278.313449)
		(end 85.74913 -278.270462)
		(width 0.088646)
		(layer "F.Cu")
		(net "M_A_CPU1_SA_DQS_DP<0>")
	)
	(arc
		(start 85.993986 -277.88997)
		(mid 85.995614 -277.879063)
		(end 85.997034 -277.868126)
		(width 0.088646)
		(layer "F.Cu")
		(net "M_A_CPU1_SA_DQS_DP<0>")
	)
	(segment
		(start 74.964798 -268.316456)
		(end 69.541898 -273.739356)
		(width 0.20066)
		(layer "F.Cu")
		(net "M_A_CPU1_SA_DQS_DN<9>")
	)
	(segment
		(start 76.690474 -267.805154)
		(end 75.423776 -267.805154)
		(width 0.1524)
		(layer "F.Cu")
		(net "M_A_CPU1_SA_DQS_DN<9>")
	)
	(segment
		(start 83.118706 -262.22833)
		(end 83.086702 -262.260334)
		(width 0.088646)
		(layer "F.Cu")
		(net "M_A_CPU1_SA_DQS_DN<9>")
	)
	(segment
		(start 63.201804 -273.980656)
		(end 63.83782 -274.405598)
		(width 0.20066)
		(layer "F.Cu")
		(net "M_A_CPU1_SA_DQS_DN<9>")
	)
	(segment
		(start 85.153246 -262.012176)
		(end 85.152992 -262.011922)
		(width 0.088646)
		(layer "F.Cu")
		(net "M_A_CPU1_SA_DQS_DN<9>")
	)
	(segment
		(start 86.470236 -262.318246)
		(end 86.468966 -262.304022)
		(width 0.088646)
		(layer "F.Cu")
		(net "M_A_CPU1_SA_DQS_DN<9>")
	)
	(segment
		(start 86.089744 -262.009636)
		(end 86.086442 -262.007858)
		(width 0.088646)
		(layer "F.Cu")
		(net "M_A_CPU1_SA_DQS_DN<9>")
	)
	(segment
		(start 86.469982 -262.318246)
		(end 86.470236 -262.318246)
		(width 0.088646)
		(layer "F.Cu")
		(net "M_A_CPU1_SA_DQS_DN<9>")
	)
	(segment
		(start 84.751164 -261.96163)
		(end 84.484464 -262.22833)
		(width 0.088646)
		(layer "F.Cu")
		(net "M_A_CPU1_SA_DQS_DN<9>")
	)
	(segment
		(start 86.397338 -262.163306)
		(end 86.092284 -262.010906)
		(width 0.088646)
		(layer "F.Cu")
		(net "M_A_CPU1_SA_DQS_DN<9>")
	)
	(segment
		(start 86.092284 -262.010906)
		(end 86.091522 -262.010652)
		(width 0.088646)
		(layer "F.Cu")
		(net "M_A_CPU1_SA_DQS_DN<9>")
	)
	(segment
		(start 62.40653 -274.241768)
		(end 62.540642 -274.241768)
		(width 0.20066)
		(layer "F.Cu")
		(net "M_A_CPU1_SA_DQS_DN<9>")
	)
	(segment
		(start 87.4141 -262.437372)
		(end 87.032846 -262.660892)
		(width 0.088646)
		(layer "F.Cu")
		(net "M_A_CPU1_SA_DQS_DN<9>")
	)
	(segment
		(start 84.484464 -262.22833)
		(end 83.118706 -262.22833)
		(width 0.088646)
		(layer "F.Cu")
		(net "M_A_CPU1_SA_DQS_DN<9>")
	)
	(segment
		(start 74.991722 -268.289532)
		(end 74.964798 -268.316456)
		(width 0.1524)
		(layer "F.Cu")
		(net "M_A_CPU1_SA_DQS_DN<9>")
	)
	(segment
		(start 58.236104 -274.405598)
		(end 58.598562 -274.405598)
		(width 0.20066)
		(layer "F.Cu")
		(net "M_A_CPU1_SA_DQS_DN<9>")
	)
	(segment
		(start 59.179968 -273.983196)
		(end 59.43854 -274.241768)
		(width 0.20066)
		(layer "F.Cu")
		(net "M_A_CPU1_SA_DQS_DN<9>")
	)
	(segment
		(start 64.55664 -274.66671)
		(end 65.047114 -274.66671)
		(width 0.20066)
		(layer "F.Cu")
		(net "M_A_CPU1_SA_DQS_DN<9>")
	)
	(segment
		(start 83.064604 -262.260334)
		(end 82.235294 -262.260334)
		(width 0.1524)
		(layer "F.Cu")
		(net "M_A_CPU1_SA_DQS_DN<9>")
	)
	(segment
		(start 84.965794 -261.96163)
		(end 84.751164 -261.96163)
		(width 0.088646)
		(layer "F.Cu")
		(net "M_A_CPU1_SA_DQS_DN<9>")
	)
	(segment
		(start 68.315078 -274.648676)
		(end 65.065148 -274.648676)
		(width 0.20066)
		(layer "F.Cu")
		(net "M_A_CPU1_SA_DQS_DN<9>")
	)
	(segment
		(start 82.235294 -262.260334)
		(end 76.690474 -267.805154)
		(width 0.1524)
		(layer "F.Cu")
		(net "M_A_CPU1_SA_DQS_DN<9>")
	)
	(segment
		(start 85.16366 -262.018272)
		(end 85.153246 -262.012176)
		(width 0.088646)
		(layer "F.Cu")
		(net "M_A_CPU1_SA_DQS_DN<9>")
	)
	(segment
		(start 58.598562 -274.405598)
		(end 59.020964 -273.983196)
		(width 0.20066)
		(layer "F.Cu")
		(net "M_A_CPU1_SA_DQS_DN<9>")
	)
	(segment
		(start 84.966048 -261.961884)
		(end 84.965794 -261.96163)
		(width 0.088646)
		(layer "F.Cu")
		(net "M_A_CPU1_SA_DQS_DN<9>")
	)
	(segment
		(start 59.020964 -273.983196)
		(end 59.179968 -273.983196)
		(width 0.20066)
		(layer "F.Cu")
		(net "M_A_CPU1_SA_DQS_DN<9>")
	)
	(segment
		(start 69.541898 -273.739356)
		(end 68.315078 -274.648676)
		(width 0.20066)
		(layer "F.Cu")
		(net "M_A_CPU1_SA_DQS_DN<9>")
	)
	(segment
		(start 65.065148 -274.648676)
		(end 65.047114 -274.66671)
		(width 0.20066)
		(layer "F.Cu")
		(net "M_A_CPU1_SA_DQS_DN<9>")
	)
	(segment
		(start 57.503314 -274.66671)
		(end 57.974992 -274.66671)
		(width 0.20066)
		(layer "F.Cu")
		(net "M_A_CPU1_SA_DQS_DN<9>")
	)
	(segment
		(start 57.974992 -274.66671)
		(end 58.236104 -274.405598)
		(width 0.20066)
		(layer "F.Cu")
		(net "M_A_CPU1_SA_DQS_DN<9>")
	)
	(segment
		(start 59.43854 -274.241768)
		(end 59.491118 -274.241768)
		(width 0.20066)
		(layer "F.Cu")
		(net "M_A_CPU1_SA_DQS_DN<9>")
	)
	(segment
		(start 62.540642 -274.241768)
		(end 62.801754 -273.980656)
		(width 0.20066)
		(layer "F.Cu")
		(net "M_A_CPU1_SA_DQS_DN<9>")
	)
	(segment
		(start 86.091522 -262.010652)
		(end 86.089744 -262.009636)
		(width 0.088646)
		(layer "F.Cu")
		(net "M_A_CPU1_SA_DQS_DN<9>")
	)
	(segment
		(start 59.491118 -274.241768)
		(end 62.40653 -274.241768)
		(width 0.1016)
		(layer "F.Cu")
		(net "M_A_CPU1_SA_DQS_DN<9>")
	)
	(segment
		(start 74.991722 -268.237208)
		(end 74.991722 -268.289532)
		(width 0.1524)
		(layer "F.Cu")
		(net "M_A_CPU1_SA_DQS_DN<9>")
	)
	(segment
		(start 85.718396 -262.011922)
		(end 85.718396 -262.012176)
		(width 0.088646)
		(layer "F.Cu")
		(net "M_A_CPU1_SA_DQS_DN<9>")
	)
	(segment
		(start 75.423776 -267.805154)
		(end 74.991722 -268.237208)
		(width 0.1524)
		(layer "F.Cu")
		(net "M_A_CPU1_SA_DQS_DN<9>")
	)
	(segment
		(start 63.83782 -274.405598)
		(end 64.295528 -274.405598)
		(width 0.20066)
		(layer "F.Cu")
		(net "M_A_CPU1_SA_DQS_DN<9>")
	)
	(segment
		(start 62.801754 -273.980656)
		(end 63.201804 -273.980656)
		(width 0.20066)
		(layer "F.Cu")
		(net "M_A_CPU1_SA_DQS_DN<9>")
	)
	(segment
		(start 86.475824 -262.396986)
		(end 86.469982 -262.318246)
		(width 0.088646)
		(layer "F.Cu")
		(net "M_A_CPU1_SA_DQS_DN<9>")
	)
	(segment
		(start 64.295528 -274.405598)
		(end 64.55664 -274.66671)
		(width 0.20066)
		(layer "F.Cu")
		(net "M_A_CPU1_SA_DQS_DN<9>")
	)
	(segment
		(start 86.468966 -262.304022)
		(end 86.397338 -262.163306)
		(width 0.088646)
		(layer "F.Cu")
		(net "M_A_CPU1_SA_DQS_DN<9>")
	)
	(segment
		(start 83.086702 -262.260334)
		(end 83.064604 -262.260334)
		(width 0.088646)
		(layer "F.Cu")
		(net "M_A_CPU1_SA_DQS_DN<9>")
	)
	(arc
		(start 87.032846 -262.660892)
		(mid 86.845648 -262.711035)
		(end 86.65845 -262.660892)
		(width 0.088646)
		(layer "F.Cu")
		(net "M_A_CPU1_SA_DQS_DN<9>")
	)
	(arc
		(start 87.785194 -262.336534)
		(mid 87.592918 -262.362191)
		(end 87.4141 -262.437372)
		(width 0.088646)
		(layer "F.Cu")
		(net "M_A_CPU1_SA_DQS_DN<9>")
	)
	(arc
		(start 86.086442 -262.007858)
		(mid 85.901896 -261.961657)
		(end 85.718396 -262.011922)
		(width 0.088646)
		(layer "F.Cu")
		(net "M_A_CPU1_SA_DQS_DN<9>")
	)
	(arc
		(start 85.718396 -262.012176)
		(mid 85.441837 -262.087919)
		(end 85.16366 -262.018272)
		(width 0.088646)
		(layer "F.Cu")
		(net "M_A_CPU1_SA_DQS_DN<9>")
	)
	(arc
		(start 86.65845 -262.660892)
		(mid 86.537483 -262.54946)
		(end 86.475824 -262.396986)
		(width 0.088646)
		(layer "F.Cu")
		(net "M_A_CPU1_SA_DQS_DN<9>")
	)
	(arc
		(start 85.152992 -262.011922)
		(mid 85.062812 -261.974601)
		(end 84.966048 -261.961884)
		(width 0.088646)
		(layer "F.Cu")
		(net "M_A_CPU1_SA_DQS_DN<9>")
	)
	(segment
		(start 63.201804 -283.33065)
		(end 63.83782 -283.755592)
		(width 0.20066)
		(layer "F.Cu")
		(net "M_A_CPU1_SA_DQS_DN<8>")
	)
	(segment
		(start 85.130132 -266.878816)
		(end 84.66455 -266.878816)
		(width 0.088646)
		(layer "F.Cu")
		(net "M_A_CPU1_SA_DQS_DN<8>")
	)
	(segment
		(start 85.718396 -266.895326)
		(end 85.651848 -266.961874)
		(width 0.088646)
		(layer "F.Cu")
		(net "M_A_CPU1_SA_DQS_DN<8>")
	)
	(segment
		(start 58.262266 -283.72943)
		(end 58.611516 -283.72943)
		(width 0.20066)
		(layer "F.Cu")
		(net "M_A_CPU1_SA_DQS_DN<8>")
	)
	(segment
		(start 62.147958 -283.601414)
		(end 62.445138 -283.601414)
		(width 0.20066)
		(layer "F.Cu")
		(net "M_A_CPU1_SA_DQS_DN<8>")
	)
	(segment
		(start 59.609736 -283.601414)
		(end 59.822842 -283.601414)
		(width 0.20066)
		(layer "F.Cu")
		(net "M_A_CPU1_SA_DQS_DN<8>")
	)
	(segment
		(start 63.83782 -283.755592)
		(end 64.295528 -283.755592)
		(width 0.20066)
		(layer "F.Cu")
		(net "M_A_CPU1_SA_DQS_DN<8>")
	)
	(segment
		(start 57.503314 -284.016704)
		(end 57.974992 -284.016704)
		(width 0.20066)
		(layer "F.Cu")
		(net "M_A_CPU1_SA_DQS_DN<8>")
	)
	(segment
		(start 86.55558 -267.483844)
		(end 86.396322 -267.324586)
		(width 0.088646)
		(layer "F.Cu")
		(net "M_A_CPU1_SA_DQS_DN<8>")
	)
	(segment
		(start 59.824366 -283.601414)
		(end 59.834018 -283.591762)
		(width 0.1016)
		(layer "F.Cu")
		(net "M_A_CPU1_SA_DQS_DN<8>")
	)
	(segment
		(start 77.33284 -274.256246)
		(end 76.00188 -276.713442)
		(width 0.1524)
		(layer "F.Cu")
		(net "M_A_CPU1_SA_DQS_DN<8>")
	)
	(segment
		(start 86.091522 -266.894056)
		(end 86.089744 -266.89304)
		(width 0.088646)
		(layer "F.Cu")
		(net "M_A_CPU1_SA_DQS_DN<8>")
	)
	(segment
		(start 83.405218 -268.138148)
		(end 83.405218 -268.183868)
		(width 0.088646)
		(layer "F.Cu")
		(net "M_A_CPU1_SA_DQS_DN<8>")
	)
	(segment
		(start 86.092284 -266.89431)
		(end 86.091522 -266.894056)
		(width 0.088646)
		(layer "F.Cu")
		(net "M_A_CPU1_SA_DQS_DN<8>")
	)
	(segment
		(start 87.785194 -267.219938)
		(end 87.21852 -267.416026)
		(width 0.088646)
		(layer "F.Cu")
		(net "M_A_CPU1_SA_DQS_DN<8>")
	)
	(segment
		(start 59.007756 -283.33319)
		(end 59.341512 -283.33319)
		(width 0.20066)
		(layer "F.Cu")
		(net "M_A_CPU1_SA_DQS_DN<8>")
	)
	(segment
		(start 64.55664 -284.016704)
		(end 65.047114 -284.016704)
		(width 0.20066)
		(layer "F.Cu")
		(net "M_A_CPU1_SA_DQS_DN<8>")
	)
	(segment
		(start 85.651848 -266.961874)
		(end 85.21319 -266.961874)
		(width 0.088646)
		(layer "F.Cu")
		(net "M_A_CPU1_SA_DQS_DN<8>")
	)
	(segment
		(start 74.493374 -281.103324)
		(end 72.168512 -283.428186)
		(width 0.20066)
		(layer "F.Cu")
		(net "M_A_CPU1_SA_DQS_DN<8>")
	)
	(segment
		(start 86.396322 -267.324586)
		(end 86.396322 -267.32484)
		(width 0.088646)
		(layer "F.Cu")
		(net "M_A_CPU1_SA_DQS_DN<8>")
	)
	(segment
		(start 70.599046 -284.016704)
		(end 65.047114 -284.016704)
		(width 0.20066)
		(layer "F.Cu")
		(net "M_A_CPU1_SA_DQS_DN<8>")
	)
	(segment
		(start 86.089744 -266.89304)
		(end 86.086442 -266.891262)
		(width 0.088646)
		(layer "F.Cu")
		(net "M_A_CPU1_SA_DQS_DN<8>")
	)
	(segment
		(start 70.884034 -283.960062)
		(end 70.599046 -284.016704)
		(width 0.20066)
		(layer "F.Cu")
		(net "M_A_CPU1_SA_DQS_DN<8>")
	)
	(segment
		(start 86.565994 -267.483844)
		(end 86.55558 -267.483844)
		(width 0.088646)
		(layer "F.Cu")
		(net "M_A_CPU1_SA_DQS_DN<8>")
	)
	(segment
		(start 83.389724 -268.199362)
		(end 77.33284 -274.256246)
		(width 0.1524)
		(layer "F.Cu")
		(net "M_A_CPU1_SA_DQS_DN<8>")
	)
	(segment
		(start 74.520298 -281.023822)
		(end 74.520298 -281.0764)
		(width 0.1524)
		(layer "F.Cu")
		(net "M_A_CPU1_SA_DQS_DN<8>")
	)
	(segment
		(start 59.834018 -283.591762)
		(end 62.127638 -283.591762)
		(width 0.1016)
		(layer "F.Cu")
		(net "M_A_CPU1_SA_DQS_DN<8>")
	)
	(segment
		(start 83.405218 -268.183868)
		(end 83.389724 -268.199362)
		(width 0.088646)
		(layer "F.Cu")
		(net "M_A_CPU1_SA_DQS_DN<8>")
	)
	(segment
		(start 72.168512 -283.428186)
		(end 70.884034 -283.960062)
		(width 0.20066)
		(layer "F.Cu")
		(net "M_A_CPU1_SA_DQS_DN<8>")
	)
	(segment
		(start 76.00188 -276.713442)
		(end 75.318112 -279.968198)
		(width 0.1524)
		(layer "F.Cu")
		(net "M_A_CPU1_SA_DQS_DN<8>")
	)
	(segment
		(start 86.16823 -266.93241)
		(end 86.092284 -266.89431)
		(width 0.088646)
		(layer "F.Cu")
		(net "M_A_CPU1_SA_DQS_DN<8>")
	)
	(segment
		(start 59.822842 -283.601414)
		(end 59.824366 -283.601414)
		(width 0.1016)
		(layer "F.Cu")
		(net "M_A_CPU1_SA_DQS_DN<8>")
	)
	(segment
		(start 75.01509 -280.529284)
		(end 74.520298 -281.023822)
		(width 0.1524)
		(layer "F.Cu")
		(net "M_A_CPU1_SA_DQS_DN<8>")
	)
	(segment
		(start 87.21852 -267.416026)
		(end 87.032846 -267.544296)
		(width 0.088646)
		(layer "F.Cu")
		(net "M_A_CPU1_SA_DQS_DN<8>")
	)
	(segment
		(start 62.13729 -283.601414)
		(end 62.147958 -283.601414)
		(width 0.1016)
		(layer "F.Cu")
		(net "M_A_CPU1_SA_DQS_DN<8>")
	)
	(segment
		(start 75.318112 -279.968198)
		(end 75.01509 -280.529284)
		(width 0.1524)
		(layer "F.Cu")
		(net "M_A_CPU1_SA_DQS_DN<8>")
	)
	(segment
		(start 58.611516 -283.72943)
		(end 59.007756 -283.33319)
		(width 0.20066)
		(layer "F.Cu")
		(net "M_A_CPU1_SA_DQS_DN<8>")
	)
	(segment
		(start 84.66455 -266.878816)
		(end 83.405218 -268.138148)
		(width 0.088646)
		(layer "F.Cu")
		(net "M_A_CPU1_SA_DQS_DN<8>")
	)
	(segment
		(start 64.295528 -283.755592)
		(end 64.55664 -284.016704)
		(width 0.20066)
		(layer "F.Cu")
		(net "M_A_CPU1_SA_DQS_DN<8>")
	)
	(segment
		(start 62.715902 -283.33065)
		(end 63.201804 -283.33065)
		(width 0.20066)
		(layer "F.Cu")
		(net "M_A_CPU1_SA_DQS_DN<8>")
	)
	(segment
		(start 59.341512 -283.33319)
		(end 59.609736 -283.601414)
		(width 0.20066)
		(layer "F.Cu")
		(net "M_A_CPU1_SA_DQS_DN<8>")
	)
	(segment
		(start 57.974992 -284.016704)
		(end 58.262266 -283.72943)
		(width 0.20066)
		(layer "F.Cu")
		(net "M_A_CPU1_SA_DQS_DN<8>")
	)
	(segment
		(start 85.21319 -266.961874)
		(end 85.130132 -266.878816)
		(width 0.088646)
		(layer "F.Cu")
		(net "M_A_CPU1_SA_DQS_DN<8>")
	)
	(segment
		(start 62.445138 -283.601414)
		(end 62.715902 -283.33065)
		(width 0.20066)
		(layer "F.Cu")
		(net "M_A_CPU1_SA_DQS_DN<8>")
	)
	(segment
		(start 86.274148 -267.140436)
		(end 86.16823 -266.93241)
		(width 0.088646)
		(layer "F.Cu")
		(net "M_A_CPU1_SA_DQS_DN<8>")
	)
	(segment
		(start 74.520298 -281.0764)
		(end 74.493374 -281.103324)
		(width 0.1524)
		(layer "F.Cu")
		(net "M_A_CPU1_SA_DQS_DN<8>")
	)
	(segment
		(start 62.127638 -283.591762)
		(end 62.13729 -283.601414)
		(width 0.1016)
		(layer "F.Cu")
		(net "M_A_CPU1_SA_DQS_DN<8>")
	)
	(arc
		(start 85.779356 -266.867132)
		(mid 85.748241 -266.879857)
		(end 85.718396 -266.895326)
		(width 0.088646)
		(layer "F.Cu")
		(net "M_A_CPU1_SA_DQS_DN<8>")
	)
	(arc
		(start 86.086442 -266.891262)
		(mid 85.935491 -266.846191)
		(end 85.779356 -266.867132)
		(width 0.088646)
		(layer "F.Cu")
		(net "M_A_CPU1_SA_DQS_DN<8>")
	)
	(arc
		(start 86.396322 -267.32484)
		(mid 86.336556 -267.245737)
		(end 86.28507 -267.16101)
		(width 0.088646)
		(layer "F.Cu")
		(net "M_A_CPU1_SA_DQS_DN<8>")
	)
	(arc
		(start 87.032846 -267.544296)
		(mid 86.845648 -267.594439)
		(end 86.65845 -267.544296)
		(width 0.088646)
		(layer "F.Cu")
		(net "M_A_CPU1_SA_DQS_DN<8>")
	)
	(arc
		(start 86.65845 -267.544296)
		(mid 86.611371 -267.515372)
		(end 86.565994 -267.483844)
		(width 0.088646)
		(layer "F.Cu")
		(net "M_A_CPU1_SA_DQS_DN<8>")
	)
	(arc
		(start 86.28507 -267.16101)
		(mid 86.279505 -267.150778)
		(end 86.274148 -267.140436)
		(width 0.088646)
		(layer "F.Cu")
		(net "M_A_CPU1_SA_DQS_DN<8>")
	)
	(segment
		(start 65.076324 -293.337488)
		(end 65.047114 -293.366698)
		(width 0.20066)
		(layer "F.Cu")
		(net "M_A_CPU1_SA_DQS_DN<7>")
	)
	(segment
		(start 86.092284 -271.777714)
		(end 86.091522 -271.77746)
		(width 0.088646)
		(layer "F.Cu")
		(net "M_A_CPU1_SA_DQS_DN<7>")
	)
	(segment
		(start 59.020964 -292.683184)
		(end 59.179968 -292.683184)
		(width 0.20066)
		(layer "F.Cu")
		(net "M_A_CPU1_SA_DQS_DN<7>")
	)
	(segment
		(start 85.116162 -272.062194)
		(end 85.059774 -272.118328)
		(width 0.088646)
		(layer "F.Cu")
		(net "M_A_CPU1_SA_DQS_DN<7>")
	)
	(segment
		(start 87.4141 -272.20418)
		(end 87.032846 -272.4277)
		(width 0.088646)
		(layer "F.Cu")
		(net "M_A_CPU1_SA_DQS_DN<7>")
	)
	(segment
		(start 78.930754 -290.153852)
		(end 78.674468 -290.410138)
		(width 0.1524)
		(layer "F.Cu")
		(net "M_A_CPU1_SA_DQS_DN<7>")
	)
	(segment
		(start 78.674468 -290.46297)
		(end 78.647544 -290.489894)
		(width 0.1524)
		(layer "F.Cu")
		(net "M_A_CPU1_SA_DQS_DN<7>")
	)
	(segment
		(start 79.077312 -281.592782)
		(end 79.077312 -289.800538)
		(width 0.1524)
		(layer "F.Cu")
		(net "M_A_CPU1_SA_DQS_DN<7>")
	)
	(segment
		(start 78.647544 -290.489894)
		(end 76.442062 -292.695376)
		(width 0.20066)
		(layer "F.Cu")
		(net "M_A_CPU1_SA_DQS_DN<7>")
	)
	(segment
		(start 59.834018 -292.941756)
		(end 62.127638 -292.941756)
		(width 0.1016)
		(layer "F.Cu")
		(net "M_A_CPU1_SA_DQS_DN<7>")
	)
	(segment
		(start 63.520066 -293.105586)
		(end 64.295528 -293.105586)
		(width 0.20066)
		(layer "F.Cu")
		(net "M_A_CPU1_SA_DQS_DN<7>")
	)
	(segment
		(start 62.127638 -292.941756)
		(end 62.13729 -292.951408)
		(width 0.1016)
		(layer "F.Cu")
		(net "M_A_CPU1_SA_DQS_DN<7>")
	)
	(segment
		(start 78.674468 -290.410138)
		(end 78.674468 -290.46297)
		(width 0.1524)
		(layer "F.Cu")
		(net "M_A_CPU1_SA_DQS_DN<7>")
	)
	(segment
		(start 83.544664 -273.67865)
		(end 80.492854 -276.73046)
		(width 0.1524)
		(layer "F.Cu")
		(net "M_A_CPU1_SA_DQS_DN<7>")
	)
	(segment
		(start 80.492854 -276.73046)
		(end 79.785464 -278.051768)
		(width 0.1524)
		(layer "F.Cu")
		(net "M_A_CPU1_SA_DQS_DN<7>")
	)
	(segment
		(start 62.273434 -292.951408)
		(end 62.544198 -292.680644)
		(width 0.20066)
		(layer "F.Cu")
		(net "M_A_CPU1_SA_DQS_DN<7>")
	)
	(segment
		(start 64.55664 -293.366698)
		(end 65.047114 -293.366698)
		(width 0.20066)
		(layer "F.Cu")
		(net "M_A_CPU1_SA_DQS_DN<7>")
	)
	(segment
		(start 64.295528 -293.105586)
		(end 64.55664 -293.366698)
		(width 0.20066)
		(layer "F.Cu")
		(net "M_A_CPU1_SA_DQS_DN<7>")
	)
	(segment
		(start 62.13729 -292.951408)
		(end 62.147958 -292.951408)
		(width 0.1016)
		(layer "F.Cu")
		(net "M_A_CPU1_SA_DQS_DN<7>")
	)
	(segment
		(start 86.468966 -272.07083)
		(end 86.397338 -271.930114)
		(width 0.088646)
		(layer "F.Cu")
		(net "M_A_CPU1_SA_DQS_DN<7>")
	)
	(segment
		(start 85.320378 -271.977358)
		(end 85.116162 -272.062194)
		(width 0.088646)
		(layer "F.Cu")
		(net "M_A_CPU1_SA_DQS_DN<7>")
	)
	(segment
		(start 85.501226 -271.977358)
		(end 85.320378 -271.977358)
		(width 0.088646)
		(layer "F.Cu")
		(net "M_A_CPU1_SA_DQS_DN<7>")
	)
	(segment
		(start 85.640418 -271.838166)
		(end 85.501226 -271.977358)
		(width 0.088646)
		(layer "F.Cu")
		(net "M_A_CPU1_SA_DQS_DN<7>")
	)
	(segment
		(start 58.236104 -293.105586)
		(end 58.598562 -293.105586)
		(width 0.20066)
		(layer "F.Cu")
		(net "M_A_CPU1_SA_DQS_DN<7>")
	)
	(segment
		(start 59.448192 -292.951408)
		(end 59.822842 -292.951408)
		(width 0.20066)
		(layer "F.Cu")
		(net "M_A_CPU1_SA_DQS_DN<7>")
	)
	(segment
		(start 86.089744 -271.776444)
		(end 86.086442 -271.774666)
		(width 0.088646)
		(layer "F.Cu")
		(net "M_A_CPU1_SA_DQS_DN<7>")
	)
	(segment
		(start 83.560158 -273.617436)
		(end 83.560158 -273.663156)
		(width 0.088646)
		(layer "F.Cu")
		(net "M_A_CPU1_SA_DQS_DN<7>")
	)
	(segment
		(start 86.091522 -271.77746)
		(end 86.089744 -271.776444)
		(width 0.088646)
		(layer "F.Cu")
		(net "M_A_CPU1_SA_DQS_DN<7>")
	)
	(segment
		(start 59.824366 -292.951408)
		(end 59.834018 -292.941756)
		(width 0.1016)
		(layer "F.Cu")
		(net "M_A_CPU1_SA_DQS_DN<7>")
	)
	(segment
		(start 85.059774 -272.118328)
		(end 85.060028 -272.118328)
		(width 0.088646)
		(layer "F.Cu")
		(net "M_A_CPU1_SA_DQS_DN<7>")
	)
	(segment
		(start 74.891646 -293.337488)
		(end 65.076324 -293.337488)
		(width 0.20066)
		(layer "F.Cu")
		(net "M_A_CPU1_SA_DQS_DN<7>")
	)
	(segment
		(start 83.730084 -273.44751)
		(end 83.560158 -273.617436)
		(width 0.088646)
		(layer "F.Cu")
		(net "M_A_CPU1_SA_DQS_DN<7>")
	)
	(segment
		(start 58.598562 -293.105586)
		(end 59.020964 -292.683184)
		(width 0.20066)
		(layer "F.Cu")
		(net "M_A_CPU1_SA_DQS_DN<7>")
	)
	(segment
		(start 86.397338 -271.930114)
		(end 86.092284 -271.777714)
		(width 0.088646)
		(layer "F.Cu")
		(net "M_A_CPU1_SA_DQS_DN<7>")
	)
	(segment
		(start 57.503314 -293.366698)
		(end 57.974992 -293.366698)
		(width 0.20066)
		(layer "F.Cu")
		(net "M_A_CPU1_SA_DQS_DN<7>")
	)
	(segment
		(start 85.640418 -271.83842)
		(end 85.640418 -271.838166)
		(width 0.088646)
		(layer "F.Cu")
		(net "M_A_CPU1_SA_DQS_DN<7>")
	)
	(segment
		(start 62.544198 -292.680644)
		(end 62.88405 -292.680644)
		(width 0.20066)
		(layer "F.Cu")
		(net "M_A_CPU1_SA_DQS_DN<7>")
	)
	(segment
		(start 62.88405 -292.680644)
		(end 63.520066 -293.105586)
		(width 0.20066)
		(layer "F.Cu")
		(net "M_A_CPU1_SA_DQS_DN<7>")
	)
	(segment
		(start 59.179968 -292.683184)
		(end 59.448192 -292.951408)
		(width 0.20066)
		(layer "F.Cu")
		(net "M_A_CPU1_SA_DQS_DN<7>")
	)
	(segment
		(start 79.785464 -278.051768)
		(end 79.077312 -281.592782)
		(width 0.1524)
		(layer "F.Cu")
		(net "M_A_CPU1_SA_DQS_DN<7>")
	)
	(segment
		(start 57.974992 -293.366698)
		(end 58.236104 -293.105586)
		(width 0.20066)
		(layer "F.Cu")
		(net "M_A_CPU1_SA_DQS_DN<7>")
	)
	(segment
		(start 83.560158 -273.663156)
		(end 83.544664 -273.67865)
		(width 0.088646)
		(layer "F.Cu")
		(net "M_A_CPU1_SA_DQS_DN<7>")
	)
	(segment
		(start 76.442062 -292.695376)
		(end 74.891646 -293.337488)
		(width 0.20066)
		(layer "F.Cu")
		(net "M_A_CPU1_SA_DQS_DN<7>")
	)
	(segment
		(start 86.470236 -272.085054)
		(end 86.468966 -272.07083)
		(width 0.088646)
		(layer "F.Cu")
		(net "M_A_CPU1_SA_DQS_DN<7>")
	)
	(segment
		(start 59.822842 -292.951408)
		(end 59.824366 -292.951408)
		(width 0.1016)
		(layer "F.Cu")
		(net "M_A_CPU1_SA_DQS_DN<7>")
	)
	(segment
		(start 85.060028 -272.118328)
		(end 83.730846 -273.44751)
		(width 0.088646)
		(layer "F.Cu")
		(net "M_A_CPU1_SA_DQS_DN<7>")
	)
	(segment
		(start 83.730846 -273.44751)
		(end 83.730084 -273.44751)
		(width 0.088646)
		(layer "F.Cu")
		(net "M_A_CPU1_SA_DQS_DN<7>")
	)
	(segment
		(start 86.469982 -272.085054)
		(end 86.470236 -272.085054)
		(width 0.088646)
		(layer "F.Cu")
		(net "M_A_CPU1_SA_DQS_DN<7>")
	)
	(segment
		(start 62.147958 -292.951408)
		(end 62.273434 -292.951408)
		(width 0.20066)
		(layer "F.Cu")
		(net "M_A_CPU1_SA_DQS_DN<7>")
	)
	(segment
		(start 79.077312 -289.800538)
		(end 78.930754 -290.153852)
		(width 0.1524)
		(layer "F.Cu")
		(net "M_A_CPU1_SA_DQS_DN<7>")
	)
	(segment
		(start 86.475824 -272.163794)
		(end 86.469982 -272.085054)
		(width 0.088646)
		(layer "F.Cu")
		(net "M_A_CPU1_SA_DQS_DN<7>")
	)
	(arc
		(start 87.785194 -272.103342)
		(mid 87.592918 -272.128999)
		(end 87.4141 -272.20418)
		(width 0.088646)
		(layer "F.Cu")
		(net "M_A_CPU1_SA_DQS_DN<7>")
	)
	(arc
		(start 85.717888 -271.77873)
		(mid 85.677201 -271.806041)
		(end 85.640418 -271.83842)
		(width 0.088646)
		(layer "F.Cu")
		(net "M_A_CPU1_SA_DQS_DN<7>")
	)
	(arc
		(start 87.032846 -272.4277)
		(mid 86.845648 -272.477843)
		(end 86.65845 -272.4277)
		(width 0.088646)
		(layer "F.Cu")
		(net "M_A_CPU1_SA_DQS_DN<7>")
	)
	(arc
		(start 86.65845 -272.4277)
		(mid 86.537483 -272.316268)
		(end 86.475824 -272.163794)
		(width 0.088646)
		(layer "F.Cu")
		(net "M_A_CPU1_SA_DQS_DN<7>")
	)
	(arc
		(start 86.086442 -271.774666)
		(mid 85.901642 -271.728343)
		(end 85.717888 -271.77873)
		(width 0.088646)
		(layer "F.Cu")
		(net "M_A_CPU1_SA_DQS_DN<7>")
	)
	(segment
		(start 91.074494 -270.197326)
		(end 91.074748 -270.19758)
		(width 0.20066)
		(layer "F.Cu")
		(net "M_A_CPU1_SA_DQS_DN<6>")
	)
	(segment
		(start 62.55131 -302.030638)
		(end 62.290198 -302.29175)
		(width 0.20066)
		(layer "F.Cu")
		(net "M_A_CPU1_SA_DQS_DN<6>")
	)
	(segment
		(start 64.295528 -302.45558)
		(end 63.591948 -302.45558)
		(width 0.20066)
		(layer "F.Cu")
		(net "M_A_CPU1_SA_DQS_DN<6>")
	)
	(segment
		(start 59.131708 -302.033178)
		(end 58.709306 -302.45558)
		(width 0.20066)
		(layer "F.Cu")
		(net "M_A_CPU1_SA_DQS_DN<6>")
	)
	(segment
		(start 64.55664 -302.716692)
		(end 64.295528 -302.45558)
		(width 0.20066)
		(layer "F.Cu")
		(net "M_A_CPU1_SA_DQS_DN<6>")
	)
	(segment
		(start 59.824366 -302.301402)
		(end 59.822842 -302.301402)
		(width 0.101854)
		(layer "F.Cu")
		(net "M_A_CPU1_SA_DQS_DN<6>")
	)
	(segment
		(start 60.070492 -302.29175)
		(end 59.834018 -302.29175)
		(width 0.101854)
		(layer "F.Cu")
		(net "M_A_CPU1_SA_DQS_DN<6>")
	)
	(segment
		(start 62.955932 -302.030638)
		(end 62.55131 -302.030638)
		(width 0.20066)
		(layer "F.Cu")
		(net "M_A_CPU1_SA_DQS_DN<6>")
	)
	(segment
		(start 62.147958 -302.29175)
		(end 60.070492 -302.29175)
		(width 0.1016)
		(layer "F.Cu")
		(net "M_A_CPU1_SA_DQS_DN<6>")
	)
	(segment
		(start 58.709306 -302.45558)
		(end 58.236104 -302.45558)
		(width 0.20066)
		(layer "F.Cu")
		(net "M_A_CPU1_SA_DQS_DN<6>")
	)
	(segment
		(start 59.822842 -302.301402)
		(end 59.639708 -302.301402)
		(width 0.20066)
		(layer "F.Cu")
		(net "M_A_CPU1_SA_DQS_DN<6>")
	)
	(segment
		(start 59.834018 -302.29175)
		(end 59.824366 -302.301402)
		(width 0.101854)
		(layer "F.Cu")
		(net "M_A_CPU1_SA_DQS_DN<6>")
	)
	(segment
		(start 58.236104 -302.45558)
		(end 57.974992 -302.716692)
		(width 0.20066)
		(layer "F.Cu")
		(net "M_A_CPU1_SA_DQS_DN<6>")
	)
	(segment
		(start 59.639708 -302.301402)
		(end 59.371484 -302.033178)
		(width 0.20066)
		(layer "F.Cu")
		(net "M_A_CPU1_SA_DQS_DN<6>")
	)
	(segment
		(start 62.290198 -302.29175)
		(end 62.147958 -302.29175)
		(width 0.20066)
		(layer "F.Cu")
		(net "M_A_CPU1_SA_DQS_DN<6>")
	)
	(segment
		(start 63.591948 -302.45558)
		(end 62.955932 -302.030638)
		(width 0.20066)
		(layer "F.Cu")
		(net "M_A_CPU1_SA_DQS_DN<6>")
	)
	(segment
		(start 59.371484 -302.033178)
		(end 59.131708 -302.033178)
		(width 0.20066)
		(layer "F.Cu")
		(net "M_A_CPU1_SA_DQS_DN<6>")
	)
	(segment
		(start 65.047114 -302.716692)
		(end 64.55664 -302.716692)
		(width 0.20066)
		(layer "F.Cu")
		(net "M_A_CPU1_SA_DQS_DN<6>")
	)
	(segment
		(start 66.152014 -302.716692)
		(end 65.047114 -302.716692)
		(width 0.20066)
		(layer "F.Cu")
		(net "M_A_CPU1_SA_DQS_DN<6>")
	)
	(segment
		(start 91.074494 -269.66164)
		(end 91.074494 -270.197326)
		(width 0.20066)
		(layer "F.Cu")
		(net "M_A_CPU1_SA_DQS_DN<6>")
	)
	(segment
		(start 57.974992 -302.716692)
		(end 57.503314 -302.716692)
		(width 0.20066)
		(layer "F.Cu")
		(net "M_A_CPU1_SA_DQS_DN<6>")
	)
	(segment
		(start 72.720708 -285.97352)
		(end 68.661788 -295.777158)
		(width 0.18288)
		(layer "In2.Cu")
		(net "M_A_CPU1_SA_DQS_DN<6>")
	)
	(segment
		(start 67.991228 -300.25213)
		(end 67.2592 -302.01997)
		(width 0.18288)
		(layer "In2.Cu")
		(net "M_A_CPU1_SA_DQS_DN<6>")
	)
	(segment
		(start 75.619356 -283.074618)
		(end 72.720708 -285.97352)
		(width 0.18288)
		(layer "In2.Cu")
		(net "M_A_CPU1_SA_DQS_DN<6>")
	)
	(segment
		(start 84.742274 -270.712692)
		(end 84.72297 -270.72082)
		(width 0.088646)
		(layer "In2.Cu")
		(net "M_A_CPU1_SA_DQS_DN<6>")
	)
	(segment
		(start 66.844926 -302.434498)
		(end 66.434208 -302.434498)
		(width 0.18288)
		(layer "In2.Cu")
		(net "M_A_CPU1_SA_DQS_DN<6>")
	)
	(segment
		(start 67.991228 -297.395646)
		(end 67.991228 -300.25213)
		(width 0.18288)
		(layer "In2.Cu")
		(net "M_A_CPU1_SA_DQS_DN<6>")
	)
	(segment
		(start 66.434208 -302.434498)
		(end 66.152014 -302.716692)
		(width 0.18288)
		(layer "In2.Cu")
		(net "M_A_CPU1_SA_DQS_DN<6>")
	)
	(segment
		(start 68.31965 -295.919144)
		(end 68.03136 -296.614596)
		(width 0.18288)
		(layer "In2.Cu")
		(net "M_A_CPU1_SA_DQS_DN<6>")
	)
	(segment
		(start 89.569544 -270.207486)
		(end 89.569544 -270.19758)
		(width 0.088646)
		(layer "In2.Cu")
		(net "M_A_CPU1_SA_DQS_DN<6>")
	)
	(segment
		(start 67.2592 -302.01997)
		(end 66.844926 -302.434498)
		(width 0.18288)
		(layer "In2.Cu")
		(net "M_A_CPU1_SA_DQS_DN<6>")
	)
	(segment
		(start 80.92948 -276.328124)
		(end 76.634848 -280.622756)
		(width 0.18288)
		(layer "In2.Cu")
		(net "M_A_CPU1_SA_DQS_DN<6>")
	)
	(segment
		(start 84.633308 -270.895064)
		(end 82.15249 -273.375882)
		(width 0.18288)
		(layer "In2.Cu")
		(net "M_A_CPU1_SA_DQS_DN<6>")
	)
	(segment
		(start 91.074748 -270.19758)
		(end 90.76182 -270.19758)
		(width 0.088646)
		(layer "In2.Cu")
		(net "M_A_CPU1_SA_DQS_DN<6>")
	)
	(segment
		(start 84.72297 -270.72082)
		(end 84.722208 -270.721074)
		(width 0.088646)
		(layer "In2.Cu")
		(net "M_A_CPU1_SA_DQS_DN<6>")
	)
	(segment
		(start 89.390982 -269.878302)
		(end 89.382092 -269.873222)
		(width 0.088646)
		(layer "In2.Cu")
		(net "M_A_CPU1_SA_DQS_DN<6>")
	)
	(segment
		(start 84.722208 -270.721074)
		(end 84.633308 -270.809974)
		(width 0.088646)
		(layer "In2.Cu")
		(net "M_A_CPU1_SA_DQS_DN<6>")
	)
	(segment
		(start 86.736428 -269.948914)
		(end 85.97265 -270.712692)
		(width 0.088646)
		(layer "In2.Cu")
		(net "M_A_CPU1_SA_DQS_DN<6>")
	)
	(segment
		(start 86.845394 -269.948914)
		(end 86.736428 -269.948914)
		(width 0.088646)
		(layer "In2.Cu")
		(net "M_A_CPU1_SA_DQS_DN<6>")
	)
	(segment
		(start 76.634848 -280.622756)
		(end 75.619356 -283.074618)
		(width 0.18288)
		(layer "In2.Cu")
		(net "M_A_CPU1_SA_DQS_DN<6>")
	)
	(segment
		(start 68.661788 -295.777158)
		(end 68.661788 -295.777412)
		(width 0.18288)
		(layer "In2.Cu")
		(net "M_A_CPU1_SA_DQS_DN<6>")
	)
	(segment
		(start 68.661788 -295.777412)
		(end 68.31965 -295.919144)
		(width 0.18288)
		(layer "In2.Cu")
		(net "M_A_CPU1_SA_DQS_DN<6>")
	)
	(segment
		(start 84.633308 -270.809974)
		(end 84.633308 -270.895064)
		(width 0.088646)
		(layer "In2.Cu")
		(net "M_A_CPU1_SA_DQS_DN<6>")
	)
	(segment
		(start 68.1736 -296.956734)
		(end 67.991228 -297.395646)
		(width 0.18288)
		(layer "In2.Cu")
		(net "M_A_CPU1_SA_DQS_DN<6>")
	)
	(segment
		(start 90.76182 -270.19758)
		(end 90.696288 -270.263112)
		(width 0.088646)
		(layer "In2.Cu")
		(net "M_A_CPU1_SA_DQS_DN<6>")
	)
	(segment
		(start 85.97265 -270.712692)
		(end 84.742274 -270.712692)
		(width 0.088646)
		(layer "In2.Cu")
		(net "M_A_CPU1_SA_DQS_DN<6>")
	)
	(segment
		(start 90.429588 -270.679926)
		(end 90.417396 -270.687038)
		(width 0.088646)
		(layer "In2.Cu")
		(net "M_A_CPU1_SA_DQS_DN<6>")
	)
	(segment
		(start 68.03136 -296.614596)
		(end 68.1736 -296.956734)
		(width 0.18288)
		(layer "In2.Cu")
		(net "M_A_CPU1_SA_DQS_DN<6>")
	)
	(segment
		(start 82.15249 -273.375882)
		(end 80.92948 -276.328124)
		(width 0.18288)
		(layer "In2.Cu")
		(net "M_A_CPU1_SA_DQS_DN<6>")
	)
	(arc
		(start 90.696288 -270.263112)
		(mid 90.694987 -270.273539)
		(end 90.693494 -270.28394)
		(width 0.088646)
		(layer "In2.Cu")
		(net "M_A_CPU1_SA_DQS_DN<6>")
	)
	(arc
		(start 89.382092 -269.873222)
		(mid 89.194894 -269.823079)
		(end 89.007696 -269.873222)
		(width 0.088646)
		(layer "In2.Cu")
		(net "M_A_CPU1_SA_DQS_DN<6>")
	)
	(arc
		(start 90.693494 -270.28394)
		(mid 90.60526 -270.511081)
		(end 90.429588 -270.679926)
		(width 0.088646)
		(layer "In2.Cu")
		(net "M_A_CPU1_SA_DQS_DN<6>")
	)
	(arc
		(start 87.502492 -269.873222)
		(mid 87.315294 -269.823079)
		(end 87.128096 -269.873222)
		(width 0.088646)
		(layer "In2.Cu")
		(net "M_A_CPU1_SA_DQS_DN<6>")
	)
	(arc
		(start 87.128096 -269.873222)
		(mid 86.991726 -269.929675)
		(end 86.845394 -269.948914)
		(width 0.088646)
		(layer "In2.Cu")
		(net "M_A_CPU1_SA_DQS_DN<6>")
	)
	(arc
		(start 89.851992 -270.687038)
		(mid 89.647657 -270.484433)
		(end 89.569544 -270.207486)
		(width 0.088646)
		(layer "In2.Cu")
		(net "M_A_CPU1_SA_DQS_DN<6>")
	)
	(arc
		(start 89.007696 -269.873222)
		(mid 88.724994 -269.948964)
		(end 88.442292 -269.873222)
		(width 0.088646)
		(layer "In2.Cu")
		(net "M_A_CPU1_SA_DQS_DN<6>")
	)
	(arc
		(start 89.569544 -270.19758)
		(mid 89.521865 -270.01468)
		(end 89.390982 -269.878302)
		(width 0.088646)
		(layer "In2.Cu")
		(net "M_A_CPU1_SA_DQS_DN<6>")
	)
	(arc
		(start 90.417396 -270.687038)
		(mid 90.134694 -270.762814)
		(end 89.851992 -270.687038)
		(width 0.088646)
		(layer "In2.Cu")
		(net "M_A_CPU1_SA_DQS_DN<6>")
	)
	(arc
		(start 88.067896 -269.873222)
		(mid 87.785194 -269.948964)
		(end 87.502492 -269.873222)
		(width 0.088646)
		(layer "In2.Cu")
		(net "M_A_CPU1_SA_DQS_DN<6>")
	)
	(arc
		(start 88.442292 -269.873222)
		(mid 88.255094 -269.823079)
		(end 88.067896 -269.873222)
		(width 0.088646)
		(layer "In2.Cu")
		(net "M_A_CPU1_SA_DQS_DN<6>")
	)
	(segment
		(start 84.292186 -278.71039)
		(end 84.388198 -278.614378)
		(width 0.088646)
		(layer "F.Cu")
		(net "M_A_CPU1_SA_DQS_DN<5>")
	)
	(segment
		(start 65.876678 -311.803542)
		(end 66.286126 -311.803542)
		(width 0.20066)
		(layer "F.Cu")
		(net "M_A_CPU1_SA_DQS_DN<5>")
	)
	(segment
		(start 59.822842 -311.651396)
		(end 59.824366 -311.651396)
		(width 0.1016)
		(layer "F.Cu")
		(net "M_A_CPU1_SA_DQS_DN<5>")
	)
	(segment
		(start 67.47002 -311.31383)
		(end 70.920356 -307.86324)
		(width 0.20066)
		(layer "F.Cu")
		(net "M_A_CPU1_SA_DQS_DN<5>")
	)
	(segment
		(start 82.988912 -282.353512)
		(end 83.558634 -279.489154)
		(width 0.1524)
		(layer "F.Cu")
		(net "M_A_CPU1_SA_DQS_DN<5>")
	)
	(segment
		(start 76.14031 -303.578768)
		(end 82.058764 -297.660314)
		(width 0.20066)
		(layer "F.Cu")
		(net "M_A_CPU1_SA_DQS_DN<5>")
	)
	(segment
		(start 66.977514 -311.517538)
		(end 67.47002 -311.31383)
		(width 0.20066)
		(layer "F.Cu")
		(net "M_A_CPU1_SA_DQS_DN<5>")
	)
	(segment
		(start 87.876634 -277.868126)
		(end 87.944198 -277.800562)
		(width 0.088646)
		(layer "F.Cu")
		(net "M_A_CPU1_SA_DQS_DN<5>")
	)
	(segment
		(start 62.13729 -311.651396)
		(end 62.147958 -311.651396)
		(width 0.1016)
		(layer "F.Cu")
		(net "M_A_CPU1_SA_DQS_DN<5>")
	)
	(segment
		(start 62.127638 -311.641744)
		(end 62.13729 -311.651396)
		(width 0.1016)
		(layer "F.Cu")
		(net "M_A_CPU1_SA_DQS_DN<5>")
	)
	(segment
		(start 62.715902 -311.380632)
		(end 63.201804 -311.380632)
		(width 0.20066)
		(layer "F.Cu")
		(net "M_A_CPU1_SA_DQS_DN<5>")
	)
	(segment
		(start 82.542634 -297.01871)
		(end 82.988912 -295.93794)
		(width 0.1524)
		(layer "F.Cu")
		(net "M_A_CPU1_SA_DQS_DN<5>")
	)
	(segment
		(start 84.961222 -277.804626)
		(end 85.041232 -277.61184)
		(width 0.088646)
		(layer "F.Cu")
		(net "M_A_CPU1_SA_DQS_DN<5>")
	)
	(segment
		(start 57.503314 -312.066686)
		(end 57.974992 -312.066686)
		(width 0.20066)
		(layer "F.Cu")
		(net "M_A_CPU1_SA_DQS_DN<5>")
	)
	(segment
		(start 58.236104 -311.805574)
		(end 58.598562 -311.805574)
		(width 0.20066)
		(layer "F.Cu")
		(net "M_A_CPU1_SA_DQS_DN<5>")
	)
	(segment
		(start 70.920356 -307.86324)
		(end 76.14031 -303.578768)
		(width 0.20066)
		(layer "F.Cu")
		(net "M_A_CPU1_SA_DQS_DN<5>")
	)
	(segment
		(start 64.295528 -311.805574)
		(end 64.55664 -312.066686)
		(width 0.20066)
		(layer "F.Cu")
		(net "M_A_CPU1_SA_DQS_DN<5>")
	)
	(segment
		(start 84.292186 -278.755602)
		(end 84.292186 -278.71039)
		(width 0.088646)
		(layer "F.Cu")
		(net "M_A_CPU1_SA_DQS_DN<5>")
	)
	(segment
		(start 86.562692 -277.476204)
		(end 86.571582 -277.481284)
		(width 0.088646)
		(layer "F.Cu")
		(net "M_A_CPU1_SA_DQS_DN<5>")
	)
	(segment
		(start 85.189822 -277.46325)
		(end 85.2805 -277.425404)
		(width 0.088646)
		(layer "F.Cu")
		(net "M_A_CPU1_SA_DQS_DN<5>")
	)
	(segment
		(start 65.047114 -312.066686)
		(end 65.613534 -312.066686)
		(width 0.20066)
		(layer "F.Cu")
		(net "M_A_CPU1_SA_DQS_DN<5>")
	)
	(segment
		(start 87.032084 -278.289512)
		(end 87.032846 -278.29002)
		(width 0.088646)
		(layer "F.Cu")
		(net "M_A_CPU1_SA_DQS_DN<5>")
	)
	(segment
		(start 82.988912 -295.93794)
		(end 82.988912 -282.353512)
		(width 0.1524)
		(layer "F.Cu")
		(net "M_A_CPU1_SA_DQS_DN<5>")
	)
	(segment
		(start 87.032846 -278.29002)
		(end 87.04326 -278.296116)
		(width 0.088646)
		(layer "F.Cu")
		(net "M_A_CPU1_SA_DQS_DN<5>")
	)
	(segment
		(start 84.388198 -278.614378)
		(end 84.50453 -278.261318)
		(width 0.088646)
		(layer "F.Cu")
		(net "M_A_CPU1_SA_DQS_DN<5>")
	)
	(segment
		(start 82.085688 -297.581066)
		(end 82.331052 -297.335702)
		(width 0.1524)
		(layer "F.Cu")
		(net "M_A_CPU1_SA_DQS_DN<5>")
	)
	(segment
		(start 84.276692 -278.771096)
		(end 84.292186 -278.755602)
		(width 0.088646)
		(layer "F.Cu")
		(net "M_A_CPU1_SA_DQS_DN<5>")
	)
	(segment
		(start 59.020964 -311.383172)
		(end 59.179968 -311.383172)
		(width 0.20066)
		(layer "F.Cu")
		(net "M_A_CPU1_SA_DQS_DN<5>")
	)
	(segment
		(start 63.83782 -311.805574)
		(end 64.295528 -311.805574)
		(width 0.20066)
		(layer "F.Cu")
		(net "M_A_CPU1_SA_DQS_DN<5>")
	)
	(segment
		(start 59.179968 -311.383172)
		(end 59.448192 -311.651396)
		(width 0.20066)
		(layer "F.Cu")
		(net "M_A_CPU1_SA_DQS_DN<5>")
	)
	(segment
		(start 62.445138 -311.651396)
		(end 62.715902 -311.380632)
		(width 0.20066)
		(layer "F.Cu")
		(net "M_A_CPU1_SA_DQS_DN<5>")
	)
	(segment
		(start 82.058764 -297.660314)
		(end 82.085688 -297.63339)
		(width 0.1524)
		(layer "F.Cu")
		(net "M_A_CPU1_SA_DQS_DN<5>")
	)
	(segment
		(start 84.50453 -278.261318)
		(end 84.961222 -277.804626)
		(width 0.088646)
		(layer "F.Cu")
		(net "M_A_CPU1_SA_DQS_DN<5>")
	)
	(segment
		(start 85.041232 -277.61184)
		(end 85.189822 -277.46325)
		(width 0.088646)
		(layer "F.Cu")
		(net "M_A_CPU1_SA_DQS_DN<5>")
	)
	(segment
		(start 83.558634 -279.489154)
		(end 84.276692 -278.771096)
		(width 0.1524)
		(layer "F.Cu")
		(net "M_A_CPU1_SA_DQS_DN<5>")
	)
	(segment
		(start 59.824366 -311.651396)
		(end 59.834018 -311.641744)
		(width 0.1016)
		(layer "F.Cu")
		(net "M_A_CPU1_SA_DQS_DN<5>")
	)
	(segment
		(start 58.598562 -311.805574)
		(end 59.020964 -311.383172)
		(width 0.20066)
		(layer "F.Cu")
		(net "M_A_CPU1_SA_DQS_DN<5>")
	)
	(segment
		(start 65.613534 -312.066686)
		(end 65.876678 -311.803542)
		(width 0.20066)
		(layer "F.Cu")
		(net "M_A_CPU1_SA_DQS_DN<5>")
	)
	(segment
		(start 59.834018 -311.641744)
		(end 62.127638 -311.641744)
		(width 0.1016)
		(layer "F.Cu")
		(net "M_A_CPU1_SA_DQS_DN<5>")
	)
	(segment
		(start 57.974992 -312.066686)
		(end 58.236104 -311.805574)
		(width 0.20066)
		(layer "F.Cu")
		(net "M_A_CPU1_SA_DQS_DN<5>")
	)
	(segment
		(start 85.2805 -277.425404)
		(end 85.435694 -277.425404)
		(width 0.088646)
		(layer "F.Cu")
		(net "M_A_CPU1_SA_DQS_DN<5>")
	)
	(segment
		(start 64.55664 -312.066686)
		(end 65.047114 -312.066686)
		(width 0.20066)
		(layer "F.Cu")
		(net "M_A_CPU1_SA_DQS_DN<5>")
	)
	(segment
		(start 82.331052 -297.335702)
		(end 82.542634 -297.01871)
		(width 0.1524)
		(layer "F.Cu")
		(net "M_A_CPU1_SA_DQS_DN<5>")
	)
	(segment
		(start 87.944198 -277.800562)
		(end 88.255094 -277.800562)
		(width 0.088646)
		(layer "F.Cu")
		(net "M_A_CPU1_SA_DQS_DN<5>")
	)
	(segment
		(start 87.02675 -278.286464)
		(end 87.032084 -278.289512)
		(width 0.088646)
		(layer "F.Cu")
		(net "M_A_CPU1_SA_DQS_DN<5>")
	)
	(segment
		(start 63.201804 -311.380632)
		(end 63.83782 -311.805574)
		(width 0.20066)
		(layer "F.Cu")
		(net "M_A_CPU1_SA_DQS_DN<5>")
	)
	(segment
		(start 62.147958 -311.651396)
		(end 62.445138 -311.651396)
		(width 0.20066)
		(layer "F.Cu")
		(net "M_A_CPU1_SA_DQS_DN<5>")
	)
	(segment
		(start 82.085688 -297.63339)
		(end 82.085688 -297.581066)
		(width 0.1524)
		(layer "F.Cu")
		(net "M_A_CPU1_SA_DQS_DN<5>")
	)
	(segment
		(start 59.448192 -311.651396)
		(end 59.822842 -311.651396)
		(width 0.20066)
		(layer "F.Cu")
		(net "M_A_CPU1_SA_DQS_DN<5>")
	)
	(segment
		(start 66.286126 -311.803542)
		(end 66.977514 -311.517538)
		(width 0.20066)
		(layer "F.Cu")
		(net "M_A_CPU1_SA_DQS_DN<5>")
	)
	(arc
		(start 86.571582 -277.481284)
		(mid 86.698836 -277.61125)
		(end 86.74989 -277.78583)
		(width 0.088646)
		(layer "F.Cu")
		(net "M_A_CPU1_SA_DQS_DN<5>")
	)
	(arc
		(start 86.74989 -277.78583)
		(mid 86.750087 -277.793195)
		(end 86.750144 -277.800562)
		(width 0.088646)
		(layer "F.Cu")
		(net "M_A_CPU1_SA_DQS_DN<5>")
	)
	(arc
		(start 86.188296 -277.476204)
		(mid 86.375494 -277.426061)
		(end 86.562692 -277.476204)
		(width 0.088646)
		(layer "F.Cu")
		(net "M_A_CPU1_SA_DQS_DN<5>")
	)
	(arc
		(start 87.597996 -278.29002)
		(mid 87.781018 -278.121005)
		(end 87.873586 -277.889716)
		(width 0.088646)
		(layer "F.Cu")
		(net "M_A_CPU1_SA_DQS_DN<5>")
	)
	(arc
		(start 85.622892 -277.476204)
		(mid 85.905594 -277.551946)
		(end 86.188296 -277.476204)
		(width 0.088646)
		(layer "F.Cu")
		(net "M_A_CPU1_SA_DQS_DN<5>")
	)
	(arc
		(start 86.750144 -277.800562)
		(mid 86.824135 -278.080128)
		(end 87.02675 -278.286464)
		(width 0.088646)
		(layer "F.Cu")
		(net "M_A_CPU1_SA_DQS_DN<5>")
	)
	(arc
		(start 87.04326 -278.296116)
		(mid 87.321438 -278.365839)
		(end 87.597996 -278.29002)
		(width 0.088646)
		(layer "F.Cu")
		(net "M_A_CPU1_SA_DQS_DN<5>")
	)
	(arc
		(start 85.435694 -277.425404)
		(mid 85.532633 -277.438494)
		(end 85.622892 -277.476204)
		(width 0.088646)
		(layer "F.Cu")
		(net "M_A_CPU1_SA_DQS_DN<5>")
	)
	(arc
		(start 87.873586 -277.889716)
		(mid 87.875216 -277.878936)
		(end 87.876634 -277.868126)
		(width 0.088646)
		(layer "F.Cu")
		(net "M_A_CPU1_SA_DQS_DN<5>")
	)
	(segment
		(start 84.361528 -262.690102)
		(end 84.168488 -262.690102)
		(width 0.088646)
		(layer "F.Cu")
		(net "M_A_CPU1_SA_DQS_DN<4>")
	)
	(segment
		(start 76.81468 -268.184122)
		(end 76.233528 -268.184122)
		(width 0.1524)
		(layer "F.Cu")
		(net "M_A_CPU1_SA_DQS_DN<4>")
	)
	(segment
		(start 74.479658 -269.886176)
		(end 74.054208 -270.311626)
		(width 0.20066)
		(layer "F.Cu")
		(net "M_A_CPU1_SA_DQS_DN<4>")
	)
	(segment
		(start 75.585828 -268.831822)
		(end 75.534012 -268.831822)
		(width 0.1524)
		(layer "F.Cu")
		(net "M_A_CPU1_SA_DQS_DN<4>")
	)
	(segment
		(start 82.734404 -262.658352)
		(end 82.34045 -262.658352)
		(width 0.1524)
		(layer "F.Cu")
		(net "M_A_CPU1_SA_DQS_DN<4>")
	)
	(segment
		(start 61.712856 -274.937728)
		(end 61.441584 -274.666456)
		(width 0.20066)
		(layer "F.Cu")
		(net "M_A_CPU1_SA_DQS_DN<4>")
	)
	(segment
		(start 83.407758 -262.601202)
		(end 83.207352 -262.601202)
		(width 0.088646)
		(layer "F.Cu")
		(net "M_A_CPU1_SA_DQS_DN<4>")
	)
	(segment
		(start 73.878186 -270.311626)
		(end 73.452228 -270.737584)
		(width 0.20066)
		(layer "F.Cu")
		(net "M_A_CPU1_SA_DQS_DN<4>")
	)
	(segment
		(start 70.369938 -273.819874)
		(end 70.369938 -273.995896)
		(width 0.20066)
		(layer "F.Cu")
		(net "M_A_CPU1_SA_DQS_DN<4>")
	)
	(segment
		(start 70.971918 -273.393916)
		(end 70.795896 -273.393916)
		(width 0.20066)
		(layer "F.Cu")
		(net "M_A_CPU1_SA_DQS_DN<4>")
	)
	(segment
		(start 73.026778 -271.339056)
		(end 72.850756 -271.339056)
		(width 0.20066)
		(layer "F.Cu")
		(net "M_A_CPU1_SA_DQS_DN<4>")
	)
	(segment
		(start 83.118452 -262.690102)
		(end 82.788252 -262.690102)
		(width 0.088646)
		(layer "F.Cu")
		(net "M_A_CPU1_SA_DQS_DN<4>")
	)
	(segment
		(start 71.999348 -272.366486)
		(end 71.823326 -272.366486)
		(width 0.20066)
		(layer "F.Cu")
		(net "M_A_CPU1_SA_DQS_DN<4>")
	)
	(segment
		(start 84.168488 -262.690102)
		(end 84.079588 -262.601202)
		(width 0.088646)
		(layer "F.Cu")
		(net "M_A_CPU1_SA_DQS_DN<4>")
	)
	(segment
		(start 66.308224 -275.091652)
		(end 63.815722 -275.091652)
		(width 0.1016)
		(layer "F.Cu")
		(net "M_A_CPU1_SA_DQS_DN<4>")
	)
	(segment
		(start 61.441584 -274.666456)
		(end 61.44133 -274.66671)
		(width 0.20066)
		(layer "F.Cu")
		(net "M_A_CPU1_SA_DQS_DN<4>")
	)
	(segment
		(start 83.879182 -262.601202)
		(end 83.790282 -262.690102)
		(width 0.088646)
		(layer "F.Cu")
		(net "M_A_CPU1_SA_DQS_DN<4>")
	)
	(segment
		(start 73.452228 -270.913606)
		(end 73.026778 -271.339056)
		(width 0.20066)
		(layer "F.Cu")
		(net "M_A_CPU1_SA_DQS_DN<4>")
	)
	(segment
		(start 70.795896 -273.393916)
		(end 70.369938 -273.819874)
		(width 0.20066)
		(layer "F.Cu")
		(net "M_A_CPU1_SA_DQS_DN<4>")
	)
	(segment
		(start 83.790282 -262.690102)
		(end 83.496658 -262.690102)
		(width 0.088646)
		(layer "F.Cu")
		(net "M_A_CPU1_SA_DQS_DN<4>")
	)
	(segment
		(start 71.397368 -272.968466)
		(end 70.971918 -273.393916)
		(width 0.20066)
		(layer "F.Cu")
		(net "M_A_CPU1_SA_DQS_DN<4>")
	)
	(segment
		(start 53.951886 -274.66671)
		(end 54.212998 -274.927822)
		(width 0.20066)
		(layer "F.Cu")
		(net "M_A_CPU1_SA_DQS_DN<4>")
	)
	(segment
		(start 84.079588 -262.601202)
		(end 83.879182 -262.601202)
		(width 0.088646)
		(layer "F.Cu")
		(net "M_A_CPU1_SA_DQS_DN<4>")
	)
	(segment
		(start 71.397368 -272.792444)
		(end 71.397368 -272.968466)
		(width 0.20066)
		(layer "F.Cu")
		(net "M_A_CPU1_SA_DQS_DN<4>")
	)
	(segment
		(start 84.966048 -262.336534)
		(end 84.790026 -262.512556)
		(width 0.088646)
		(layer "F.Cu")
		(net "M_A_CPU1_SA_DQS_DN<4>")
	)
	(segment
		(start 72.424798 -271.765014)
		(end 72.424798 -271.941036)
		(width 0.20066)
		(layer "F.Cu")
		(net "M_A_CPU1_SA_DQS_DN<4>")
	)
	(segment
		(start 72.424798 -271.941036)
		(end 71.999348 -272.366486)
		(width 0.20066)
		(layer "F.Cu")
		(net "M_A_CPU1_SA_DQS_DN<4>")
	)
	(segment
		(start 56.036464 -275.091652)
		(end 58.744612 -275.091652)
		(width 0.1016)
		(layer "F.Cu")
		(net "M_A_CPU1_SA_DQS_DN<4>")
	)
	(segment
		(start 55.94477 -275.091652)
		(end 56.036464 -275.091652)
		(width 0.20066)
		(layer "F.Cu")
		(net "M_A_CPU1_SA_DQS_DN<4>")
	)
	(segment
		(start 68.043044 -275.472652)
		(end 66.664586 -275.472652)
		(width 0.20066)
		(layer "F.Cu")
		(net "M_A_CPU1_SA_DQS_DN<4>")
	)
	(segment
		(start 54.212998 -274.927822)
		(end 54.579012 -274.927822)
		(width 0.20066)
		(layer "F.Cu")
		(net "M_A_CPU1_SA_DQS_DN<4>")
	)
	(segment
		(start 75.507088 -268.858746)
		(end 75.081638 -269.284196)
		(width 0.20066)
		(layer "F.Cu")
		(net "M_A_CPU1_SA_DQS_DN<4>")
	)
	(segment
		(start 72.850756 -271.339056)
		(end 72.424798 -271.765014)
		(width 0.20066)
		(layer "F.Cu")
		(net "M_A_CPU1_SA_DQS_DN<4>")
	)
	(segment
		(start 74.054208 -270.311626)
		(end 73.878186 -270.311626)
		(width 0.20066)
		(layer "F.Cu")
		(net "M_A_CPU1_SA_DQS_DN<4>")
	)
	(segment
		(start 62.922912 -275.359114)
		(end 61.905642 -274.937728)
		(width 0.20066)
		(layer "F.Cu")
		(net "M_A_CPU1_SA_DQS_DN<4>")
	)
	(segment
		(start 76.233528 -268.184122)
		(end 75.585828 -268.831822)
		(width 0.1524)
		(layer "F.Cu")
		(net "M_A_CPU1_SA_DQS_DN<4>")
	)
	(segment
		(start 69.966332 -274.399502)
		(end 68.877942 -275.126704)
		(width 0.20066)
		(layer "F.Cu")
		(net "M_A_CPU1_SA_DQS_DN<4>")
	)
	(segment
		(start 74.905616 -269.284196)
		(end 74.479658 -269.710154)
		(width 0.20066)
		(layer "F.Cu")
		(net "M_A_CPU1_SA_DQS_DN<4>")
	)
	(segment
		(start 84.790026 -262.512556)
		(end 84.361528 -262.690102)
		(width 0.088646)
		(layer "F.Cu")
		(net "M_A_CPU1_SA_DQS_DN<4>")
	)
	(segment
		(start 63.815722 -275.091652)
		(end 63.7159 -275.091652)
		(width 0.20066)
		(layer "F.Cu")
		(net "M_A_CPU1_SA_DQS_DN<4>")
	)
	(segment
		(start 71.823326 -272.366486)
		(end 71.397368 -272.792444)
		(width 0.20066)
		(layer "F.Cu")
		(net "M_A_CPU1_SA_DQS_DN<4>")
	)
	(segment
		(start 66.46291 -275.091652)
		(end 66.308224 -275.091652)
		(width 0.20066)
		(layer "F.Cu")
		(net "M_A_CPU1_SA_DQS_DN<4>")
	)
	(segment
		(start 82.756502 -262.658352)
		(end 82.734404 -262.658352)
		(width 0.088646)
		(layer "F.Cu")
		(net "M_A_CPU1_SA_DQS_DN<4>")
	)
	(segment
		(start 55.215028 -275.353018)
		(end 55.683404 -275.353018)
		(width 0.20066)
		(layer "F.Cu")
		(net "M_A_CPU1_SA_DQS_DN<4>")
	)
	(segment
		(start 68.877942 -275.126704)
		(end 68.043044 -275.472652)
		(width 0.20066)
		(layer "F.Cu")
		(net "M_A_CPU1_SA_DQS_DN<4>")
	)
	(segment
		(start 59.205876 -275.353018)
		(end 59.379612 -275.280882)
		(width 0.20066)
		(layer "F.Cu")
		(net "M_A_CPU1_SA_DQS_DN<4>")
	)
	(segment
		(start 58.85942 -275.091652)
		(end 59.120786 -275.353018)
		(width 0.20066)
		(layer "F.Cu")
		(net "M_A_CPU1_SA_DQS_DN<4>")
	)
	(segment
		(start 59.732672 -274.927822)
		(end 60.139326 -274.927822)
		(width 0.20066)
		(layer "F.Cu")
		(net "M_A_CPU1_SA_DQS_DN<4>")
	)
	(segment
		(start 63.448438 -275.359114)
		(end 62.922912 -275.359114)
		(width 0.20066)
		(layer "F.Cu")
		(net "M_A_CPU1_SA_DQS_DN<4>")
	)
	(segment
		(start 61.44133 -274.66671)
		(end 60.947046 -274.66671)
		(width 0.20066)
		(layer "F.Cu")
		(net "M_A_CPU1_SA_DQS_DN<4>")
	)
	(segment
		(start 82.788252 -262.690102)
		(end 82.756502 -262.658352)
		(width 0.088646)
		(layer "F.Cu")
		(net "M_A_CPU1_SA_DQS_DN<4>")
	)
	(segment
		(start 53.403246 -274.66671)
		(end 53.951886 -274.66671)
		(width 0.20066)
		(layer "F.Cu")
		(net "M_A_CPU1_SA_DQS_DN<4>")
	)
	(segment
		(start 54.579012 -274.927822)
		(end 55.215028 -275.353018)
		(width 0.20066)
		(layer "F.Cu")
		(net "M_A_CPU1_SA_DQS_DN<4>")
	)
	(segment
		(start 66.664586 -275.472652)
		(end 66.56578 -275.373846)
		(width 0.20066)
		(layer "F.Cu")
		(net "M_A_CPU1_SA_DQS_DN<4>")
	)
	(segment
		(start 59.120786 -275.353018)
		(end 59.205876 -275.353018)
		(width 0.20066)
		(layer "F.Cu")
		(net "M_A_CPU1_SA_DQS_DN<4>")
	)
	(segment
		(start 58.744612 -275.091652)
		(end 58.85942 -275.091652)
		(width 0.20066)
		(layer "F.Cu")
		(net "M_A_CPU1_SA_DQS_DN<4>")
	)
	(segment
		(start 63.7159 -275.091652)
		(end 63.448438 -275.359114)
		(width 0.20066)
		(layer "F.Cu")
		(net "M_A_CPU1_SA_DQS_DN<4>")
	)
	(segment
		(start 70.369938 -273.995896)
		(end 69.966332 -274.399502)
		(width 0.20066)
		(layer "F.Cu")
		(net "M_A_CPU1_SA_DQS_DN<4>")
	)
	(segment
		(start 60.139326 -274.927822)
		(end 60.400438 -274.66671)
		(width 0.20066)
		(layer "F.Cu")
		(net "M_A_CPU1_SA_DQS_DN<4>")
	)
	(segment
		(start 73.452228 -270.737584)
		(end 73.452228 -270.913606)
		(width 0.20066)
		(layer "F.Cu")
		(net "M_A_CPU1_SA_DQS_DN<4>")
	)
	(segment
		(start 74.479658 -269.710154)
		(end 74.479658 -269.886176)
		(width 0.20066)
		(layer "F.Cu")
		(net "M_A_CPU1_SA_DQS_DN<4>")
	)
	(segment
		(start 66.56578 -275.373846)
		(end 66.56578 -275.194522)
		(width 0.20066)
		(layer "F.Cu")
		(net "M_A_CPU1_SA_DQS_DN<4>")
	)
	(segment
		(start 75.534012 -268.831822)
		(end 75.507088 -268.858746)
		(width 0.1524)
		(layer "F.Cu")
		(net "M_A_CPU1_SA_DQS_DN<4>")
	)
	(segment
		(start 59.379612 -275.280882)
		(end 59.732672 -274.927822)
		(width 0.20066)
		(layer "F.Cu")
		(net "M_A_CPU1_SA_DQS_DN<4>")
	)
	(segment
		(start 61.905642 -274.937728)
		(end 61.712856 -274.937728)
		(width 0.20066)
		(layer "F.Cu")
		(net "M_A_CPU1_SA_DQS_DN<4>")
	)
	(segment
		(start 75.081638 -269.284196)
		(end 74.905616 -269.284196)
		(width 0.20066)
		(layer "F.Cu")
		(net "M_A_CPU1_SA_DQS_DN<4>")
	)
	(segment
		(start 60.400438 -274.66671)
		(end 60.947046 -274.66671)
		(width 0.20066)
		(layer "F.Cu")
		(net "M_A_CPU1_SA_DQS_DN<4>")
	)
	(segment
		(start 82.34045 -262.658352)
		(end 76.81468 -268.184122)
		(width 0.1524)
		(layer "F.Cu")
		(net "M_A_CPU1_SA_DQS_DN<4>")
	)
	(segment
		(start 66.56578 -275.194522)
		(end 66.46291 -275.091652)
		(width 0.20066)
		(layer "F.Cu")
		(net "M_A_CPU1_SA_DQS_DN<4>")
	)
	(segment
		(start 83.496658 -262.690102)
		(end 83.407758 -262.601202)
		(width 0.088646)
		(layer "F.Cu")
		(net "M_A_CPU1_SA_DQS_DN<4>")
	)
	(segment
		(start 83.207352 -262.601202)
		(end 83.118452 -262.690102)
		(width 0.088646)
		(layer "F.Cu")
		(net "M_A_CPU1_SA_DQS_DN<4>")
	)
	(segment
		(start 55.683404 -275.353018)
		(end 55.94477 -275.091652)
		(width 0.20066)
		(layer "F.Cu")
		(net "M_A_CPU1_SA_DQS_DN<4>")
	)
	(segment
		(start 66.237612 -284.42412)
		(end 66.220086 -284.441646)
		(width 0.1016)
		(layer "F.Cu")
		(net "M_A_CPU1_SA_DQS_DN<3>")
	)
	(segment
		(start 63.539624 -284.424882)
		(end 63.255398 -284.709108)
		(width 0.20066)
		(layer "F.Cu")
		(net "M_A_CPU1_SA_DQS_DN<3>")
	)
	(segment
		(start 83.818476 -268.480286)
		(end 83.541108 -268.595348)
		(width 0.088646)
		(layer "F.Cu")
		(net "M_A_CPU1_SA_DQS_DN<3>")
	)
	(segment
		(start 84.033106 -268.125702)
		(end 83.853274 -268.305534)
		(width 0.088646)
		(layer "F.Cu")
		(net "M_A_CPU1_SA_DQS_DN<3>")
	)
	(segment
		(start 58.892948 -284.441646)
		(end 59.154314 -284.703012)
		(width 0.20066)
		(layer "F.Cu")
		(net "M_A_CPU1_SA_DQS_DN<3>")
	)
	(segment
		(start 77.621638 -274.470368)
		(end 76.33462 -276.878034)
		(width 0.1524)
		(layer "F.Cu")
		(net "M_A_CPU1_SA_DQS_DN<3>")
	)
	(segment
		(start 70.01129 -284.919166)
		(end 69.666866 -284.919166)
		(width 0.20066)
		(layer "F.Cu")
		(net "M_A_CPU1_SA_DQS_DN<3>")
	)
	(segment
		(start 83.541108 -268.595348)
		(end 82.986372 -269.150338)
		(width 0.088646)
		(layer "F.Cu")
		(net "M_A_CPU1_SA_DQS_DN<3>")
	)
	(segment
		(start 61.712856 -284.287722)
		(end 61.441584 -284.01645)
		(width 0.20066)
		(layer "F.Cu")
		(net "M_A_CPU1_SA_DQS_DN<3>")
	)
	(segment
		(start 73.306432 -283.381196)
		(end 73.13041 -283.381196)
		(width 0.20066)
		(layer "F.Cu")
		(net "M_A_CPU1_SA_DQS_DN<3>")
	)
	(segment
		(start 82.926174 -269.165832)
		(end 77.621638 -274.470368)
		(width 0.1524)
		(layer "F.Cu")
		(net "M_A_CPU1_SA_DQS_DN<3>")
	)
	(segment
		(start 55.401718 -284.703012)
		(end 55.710328 -284.703012)
		(width 0.20066)
		(layer "F.Cu")
		(net "M_A_CPU1_SA_DQS_DN<3>")
	)
	(segment
		(start 74.759312 -281.928316)
		(end 74.333862 -282.353766)
		(width 0.20066)
		(layer "F.Cu")
		(net "M_A_CPU1_SA_DQS_DN<3>")
	)
	(segment
		(start 69.542406 -284.794706)
		(end 68.940426 -284.794706)
		(width 0.20066)
		(layer "F.Cu")
		(net "M_A_CPU1_SA_DQS_DN<3>")
	)
	(segment
		(start 70.712838 -284.77972)
		(end 70.01129 -284.919166)
		(width 0.20066)
		(layer "F.Cu")
		(net "M_A_CPU1_SA_DQS_DN<3>")
	)
	(segment
		(start 82.941668 -269.150338)
		(end 82.926174 -269.165832)
		(width 0.088646)
		(layer "F.Cu")
		(net "M_A_CPU1_SA_DQS_DN<3>")
	)
	(segment
		(start 60.400438 -284.016704)
		(end 60.947046 -284.016704)
		(width 0.20066)
		(layer "F.Cu")
		(net "M_A_CPU1_SA_DQS_DN<3>")
	)
	(segment
		(start 56.379872 -284.430978)
		(end 56.39054 -284.441646)
		(width 0.1016)
		(layer "F.Cu")
		(net "M_A_CPU1_SA_DQS_DN<3>")
	)
	(segment
		(start 84.966048 -267.219938)
		(end 84.8106 -267.487654)
		(width 0.088646)
		(layer "F.Cu")
		(net "M_A_CPU1_SA_DQS_DN<3>")
	)
	(segment
		(start 72.704452 -283.807154)
		(end 72.704452 -283.983176)
		(width 0.20066)
		(layer "F.Cu")
		(net "M_A_CPU1_SA_DQS_DN<3>")
	)
	(segment
		(start 55.982362 -284.430978)
		(end 56.37911 -284.430978)
		(width 0.20066)
		(layer "F.Cu")
		(net "M_A_CPU1_SA_DQS_DN<3>")
	)
	(segment
		(start 68.940426 -284.794706)
		(end 68.815966 -284.919166)
		(width 0.20066)
		(layer "F.Cu")
		(net "M_A_CPU1_SA_DQS_DN<3>")
	)
	(segment
		(start 58.694828 -284.441646)
		(end 58.704226 -284.441646)
		(width 0.101854)
		(layer "F.Cu")
		(net "M_A_CPU1_SA_DQS_DN<3>")
	)
	(segment
		(start 53.951886 -284.016704)
		(end 54.212998 -284.277816)
		(width 0.20066)
		(layer "F.Cu")
		(net "M_A_CPU1_SA_DQS_DN<3>")
	)
	(segment
		(start 75.685142 -280.14295)
		(end 75.685142 -280.143458)
		(width 0.1524)
		(layer "F.Cu")
		(net "M_A_CPU1_SA_DQS_DN<3>")
	)
	(segment
		(start 68.213986 -284.919166)
		(end 68.089526 -284.794706)
		(width 0.20066)
		(layer "F.Cu")
		(net "M_A_CPU1_SA_DQS_DN<3>")
	)
	(segment
		(start 72.704452 -283.983176)
		(end 72.204834 -284.482794)
		(width 0.20066)
		(layer "F.Cu")
		(net "M_A_CPU1_SA_DQS_DN<3>")
	)
	(segment
		(start 84.17306 -268.125702)
		(end 84.033106 -268.125702)
		(width 0.088646)
		(layer "F.Cu")
		(net "M_A_CPU1_SA_DQS_DN<3>")
	)
	(segment
		(start 83.853274 -268.445488)
		(end 83.818476 -268.480286)
		(width 0.088646)
		(layer "F.Cu")
		(net "M_A_CPU1_SA_DQS_DN<3>")
	)
	(segment
		(start 75.685142 -280.143458)
		(end 75.12685 -281.612594)
		(width 0.1524)
		(layer "F.Cu")
		(net "M_A_CPU1_SA_DQS_DN<3>")
	)
	(segment
		(start 73.731882 -282.779724)
		(end 73.731882 -282.955746)
		(width 0.20066)
		(layer "F.Cu")
		(net "M_A_CPU1_SA_DQS_DN<3>")
	)
	(segment
		(start 69.666866 -284.919166)
		(end 69.542406 -284.794706)
		(width 0.20066)
		(layer "F.Cu")
		(net "M_A_CPU1_SA_DQS_DN<3>")
	)
	(segment
		(start 56.37911 -284.430978)
		(end 56.379872 -284.430978)
		(width 0.1016)
		(layer "F.Cu")
		(net "M_A_CPU1_SA_DQS_DN<3>")
	)
	(segment
		(start 74.15784 -282.353766)
		(end 73.731882 -282.779724)
		(width 0.20066)
		(layer "F.Cu")
		(net "M_A_CPU1_SA_DQS_DN<3>")
	)
	(segment
		(start 63.255398 -284.709108)
		(end 63.071502 -284.709108)
		(width 0.20066)
		(layer "F.Cu")
		(net "M_A_CPU1_SA_DQS_DN<3>")
	)
	(segment
		(start 66.78803 -284.733238)
		(end 66.78803 -284.52699)
		(width 0.20066)
		(layer "F.Cu")
		(net "M_A_CPU1_SA_DQS_DN<3>")
	)
	(segment
		(start 74.333862 -282.353766)
		(end 74.15784 -282.353766)
		(width 0.20066)
		(layer "F.Cu")
		(net "M_A_CPU1_SA_DQS_DN<3>")
	)
	(segment
		(start 67.363086 -284.919166)
		(end 66.973958 -284.919166)
		(width 0.20066)
		(layer "F.Cu")
		(net "M_A_CPU1_SA_DQS_DN<3>")
	)
	(segment
		(start 54.765702 -284.277816)
		(end 55.401718 -284.703012)
		(width 0.20066)
		(layer "F.Cu")
		(net "M_A_CPU1_SA_DQS_DN<3>")
	)
	(segment
		(start 84.511642 -267.647166)
		(end 84.33181 -267.826998)
		(width 0.088646)
		(layer "F.Cu")
		(net "M_A_CPU1_SA_DQS_DN<3>")
	)
	(segment
		(start 76.33462 -276.878034)
		(end 75.685142 -280.14295)
		(width 0.1524)
		(layer "F.Cu")
		(net "M_A_CPU1_SA_DQS_DN<3>")
	)
	(segment
		(start 82.986372 -269.150338)
		(end 82.941668 -269.150338)
		(width 0.088646)
		(layer "F.Cu")
		(net "M_A_CPU1_SA_DQS_DN<3>")
	)
	(segment
		(start 84.755482 -267.542772)
		(end 84.755482 -267.54328)
		(width 0.088646)
		(layer "F.Cu")
		(net "M_A_CPU1_SA_DQS_DN<3>")
	)
	(segment
		(start 73.13041 -283.381196)
		(end 72.704452 -283.807154)
		(width 0.20066)
		(layer "F.Cu")
		(net "M_A_CPU1_SA_DQS_DN<3>")
	)
	(segment
		(start 84.755482 -267.54328)
		(end 84.651596 -267.647166)
		(width 0.088646)
		(layer "F.Cu")
		(net "M_A_CPU1_SA_DQS_DN<3>")
	)
	(segment
		(start 84.33181 -267.826998)
		(end 84.33181 -267.966952)
		(width 0.088646)
		(layer "F.Cu")
		(net "M_A_CPU1_SA_DQS_DN<3>")
	)
	(segment
		(start 59.841384 -284.277816)
		(end 60.139326 -284.277816)
		(width 0.20066)
		(layer "F.Cu")
		(net "M_A_CPU1_SA_DQS_DN<3>")
	)
	(segment
		(start 54.212998 -284.277816)
		(end 54.765702 -284.277816)
		(width 0.20066)
		(layer "F.Cu")
		(net "M_A_CPU1_SA_DQS_DN<3>")
	)
	(segment
		(start 59.154314 -284.703012)
		(end 59.416188 -284.703012)
		(width 0.20066)
		(layer "F.Cu")
		(net "M_A_CPU1_SA_DQS_DN<3>")
	)
	(segment
		(start 71.401178 -284.51556)
		(end 70.810628 -284.633162)
		(width 0.20066)
		(layer "F.Cu")
		(net "M_A_CPU1_SA_DQS_DN<3>")
	)
	(segment
		(start 58.704226 -284.441646)
		(end 58.892948 -284.441646)
		(width 0.20066)
		(layer "F.Cu")
		(net "M_A_CPU1_SA_DQS_DN<3>")
	)
	(segment
		(start 61.44133 -284.016704)
		(end 60.947046 -284.016704)
		(width 0.20066)
		(layer "F.Cu")
		(net "M_A_CPU1_SA_DQS_DN<3>")
	)
	(segment
		(start 84.8106 -267.487654)
		(end 84.755482 -267.542772)
		(width 0.088646)
		(layer "F.Cu")
		(net "M_A_CPU1_SA_DQS_DN<3>")
	)
	(segment
		(start 55.710328 -284.703012)
		(end 55.982362 -284.430978)
		(width 0.20066)
		(layer "F.Cu")
		(net "M_A_CPU1_SA_DQS_DN<3>")
	)
	(segment
		(start 75.12685 -281.612594)
		(end 74.838052 -281.901392)
		(width 0.1524)
		(layer "F.Cu")
		(net "M_A_CPU1_SA_DQS_DN<3>")
	)
	(segment
		(start 71.547482 -284.61335)
		(end 71.401178 -284.51556)
		(width 0.20066)
		(layer "F.Cu")
		(net "M_A_CPU1_SA_DQS_DN<3>")
	)
	(segment
		(start 59.416188 -284.703012)
		(end 59.841384 -284.277816)
		(width 0.20066)
		(layer "F.Cu")
		(net "M_A_CPU1_SA_DQS_DN<3>")
	)
	(segment
		(start 53.403246 -284.016704)
		(end 53.951886 -284.016704)
		(width 0.20066)
		(layer "F.Cu")
		(net "M_A_CPU1_SA_DQS_DN<3>")
	)
	(segment
		(start 63.951612 -284.424882)
		(end 63.539624 -284.424882)
		(width 0.20066)
		(layer "F.Cu")
		(net "M_A_CPU1_SA_DQS_DN<3>")
	)
	(segment
		(start 61.441584 -284.01645)
		(end 61.44133 -284.016704)
		(width 0.20066)
		(layer "F.Cu")
		(net "M_A_CPU1_SA_DQS_DN<3>")
	)
	(segment
		(start 72.204834 -284.482794)
		(end 71.547482 -284.61335)
		(width 0.20066)
		(layer "F.Cu")
		(net "M_A_CPU1_SA_DQS_DN<3>")
	)
	(segment
		(start 66.973958 -284.919166)
		(end 66.78803 -284.733238)
		(width 0.20066)
		(layer "F.Cu")
		(net "M_A_CPU1_SA_DQS_DN<3>")
	)
	(segment
		(start 62.054232 -284.287722)
		(end 61.712856 -284.287722)
		(width 0.20066)
		(layer "F.Cu")
		(net "M_A_CPU1_SA_DQS_DN<3>")
	)
	(segment
		(start 63.071502 -284.709108)
		(end 62.054232 -284.287722)
		(width 0.20066)
		(layer "F.Cu")
		(net "M_A_CPU1_SA_DQS_DN<3>")
	)
	(segment
		(start 60.139326 -284.277816)
		(end 60.400438 -284.016704)
		(width 0.20066)
		(layer "F.Cu")
		(net "M_A_CPU1_SA_DQS_DN<3>")
	)
	(segment
		(start 66.78803 -284.52699)
		(end 66.68516 -284.42412)
		(width 0.20066)
		(layer "F.Cu")
		(net "M_A_CPU1_SA_DQS_DN<3>")
	)
	(segment
		(start 67.487546 -284.794706)
		(end 67.363086 -284.919166)
		(width 0.20066)
		(layer "F.Cu")
		(net "M_A_CPU1_SA_DQS_DN<3>")
	)
	(segment
		(start 68.089526 -284.794706)
		(end 67.487546 -284.794706)
		(width 0.20066)
		(layer "F.Cu")
		(net "M_A_CPU1_SA_DQS_DN<3>")
	)
	(segment
		(start 83.853274 -268.305534)
		(end 83.853274 -268.445488)
		(width 0.088646)
		(layer "F.Cu")
		(net "M_A_CPU1_SA_DQS_DN<3>")
	)
	(segment
		(start 63.968376 -284.441646)
		(end 63.951612 -284.424882)
		(width 0.1016)
		(layer "F.Cu")
		(net "M_A_CPU1_SA_DQS_DN<3>")
	)
	(segment
		(start 66.68516 -284.42412)
		(end 66.237612 -284.42412)
		(width 0.20066)
		(layer "F.Cu")
		(net "M_A_CPU1_SA_DQS_DN<3>")
	)
	(segment
		(start 73.731882 -282.955746)
		(end 73.306432 -283.381196)
		(width 0.20066)
		(layer "F.Cu")
		(net "M_A_CPU1_SA_DQS_DN<3>")
	)
	(segment
		(start 70.810628 -284.633162)
		(end 70.712838 -284.77972)
		(width 0.20066)
		(layer "F.Cu")
		(net "M_A_CPU1_SA_DQS_DN<3>")
	)
	(segment
		(start 68.815966 -284.919166)
		(end 68.213986 -284.919166)
		(width 0.20066)
		(layer "F.Cu")
		(net "M_A_CPU1_SA_DQS_DN<3>")
	)
	(segment
		(start 84.651596 -267.647166)
		(end 84.511642 -267.647166)
		(width 0.088646)
		(layer "F.Cu")
		(net "M_A_CPU1_SA_DQS_DN<3>")
	)
	(segment
		(start 84.33181 -267.966952)
		(end 84.17306 -268.125702)
		(width 0.088646)
		(layer "F.Cu")
		(net "M_A_CPU1_SA_DQS_DN<3>")
	)
	(segment
		(start 56.39054 -284.441646)
		(end 58.694828 -284.441646)
		(width 0.1016)
		(layer "F.Cu")
		(net "M_A_CPU1_SA_DQS_DN<3>")
	)
	(segment
		(start 74.786236 -281.901392)
		(end 74.759312 -281.928316)
		(width 0.1524)
		(layer "F.Cu")
		(net "M_A_CPU1_SA_DQS_DN<3>")
	)
	(segment
		(start 66.220086 -284.441646)
		(end 63.968376 -284.441646)
		(width 0.1016)
		(layer "F.Cu")
		(net "M_A_CPU1_SA_DQS_DN<3>")
	)
	(segment
		(start 74.838052 -281.901392)
		(end 74.786236 -281.901392)
		(width 0.1524)
		(layer "F.Cu")
		(net "M_A_CPU1_SA_DQS_DN<3>")
	)
	(segment
		(start 78.762606 -291.455856)
		(end 78.586584 -291.455856)
		(width 0.20066)
		(layer "F.Cu")
		(net "M_A_CPU1_SA_DQS_DN<2>")
	)
	(segment
		(start 73.146158 -294.313864)
		(end 72.544178 -294.313864)
		(width 0.20066)
		(layer "F.Cu")
		(net "M_A_CPU1_SA_DQS_DN<2>")
	)
	(segment
		(start 77.559154 -292.483286)
		(end 77.133196 -292.909244)
		(width 0.20066)
		(layer "F.Cu")
		(net "M_A_CPU1_SA_DQS_DN<2>")
	)
	(segment
		(start 70.92442 -294.189404)
		(end 70.32244 -294.189404)
		(width 0.20066)
		(layer "F.Cu")
		(net "M_A_CPU1_SA_DQS_DN<2>")
	)
	(segment
		(start 66.359024 -293.79164)
		(end 66.237612 -293.79164)
		(width 0.20066)
		(layer "F.Cu")
		(net "M_A_CPU1_SA_DQS_DN<2>")
	)
	(segment
		(start 63.148972 -294.117014)
		(end 61.942726 -293.617396)
		(width 0.20066)
		(layer "F.Cu")
		(net "M_A_CPU1_SA_DQS_DN<2>")
	)
	(segment
		(start 60.139326 -293.62781)
		(end 60.400438 -293.366698)
		(width 0.20066)
		(layer "F.Cu")
		(net "M_A_CPU1_SA_DQS_DN<2>")
	)
	(segment
		(start 53.403246 -293.366698)
		(end 53.951886 -293.366698)
		(width 0.20066)
		(layer "F.Cu")
		(net "M_A_CPU1_SA_DQS_DN<2>")
	)
	(segment
		(start 73.997058 -294.313864)
		(end 73.872598 -294.189404)
		(width 0.20066)
		(layer "F.Cu")
		(net "M_A_CPU1_SA_DQS_DN<2>")
	)
	(segment
		(start 74.537824 -294.313864)
		(end 73.997058 -294.313864)
		(width 0.20066)
		(layer "F.Cu")
		(net "M_A_CPU1_SA_DQS_DN<2>")
	)
	(segment
		(start 71.04888 -294.313864)
		(end 70.92442 -294.189404)
		(width 0.20066)
		(layer "F.Cu")
		(net "M_A_CPU1_SA_DQS_DN<2>")
	)
	(segment
		(start 76.871322 -293.347394)
		(end 75.994006 -293.710614)
		(width 0.20066)
		(layer "F.Cu")
		(net "M_A_CPU1_SA_DQS_DN<2>")
	)
	(segment
		(start 80.781652 -276.944836)
		(end 80.123792 -278.176736)
		(width 0.1524)
		(layer "F.Cu")
		(net "M_A_CPU1_SA_DQS_DN<2>")
	)
	(segment
		(start 79.266796 -291.003482)
		(end 79.21498 -291.003482)
		(width 0.1524)
		(layer "F.Cu")
		(net "M_A_CPU1_SA_DQS_DN<2>")
	)
	(segment
		(start 66.595244 -294.218868)
		(end 66.595244 -294.02786)
		(width 0.20066)
		(layer "F.Cu")
		(net "M_A_CPU1_SA_DQS_DN<2>")
	)
	(segment
		(start 71.817738 -294.189404)
		(end 71.693278 -294.313864)
		(width 0.20066)
		(layer "F.Cu")
		(net "M_A_CPU1_SA_DQS_DN<2>")
	)
	(segment
		(start 53.951886 -293.366698)
		(end 54.212998 -293.62781)
		(width 0.20066)
		(layer "F.Cu")
		(net "M_A_CPU1_SA_DQS_DN<2>")
	)
	(segment
		(start 63.545212 -294.035988)
		(end 63.464186 -294.117014)
		(width 0.20066)
		(layer "F.Cu")
		(net "M_A_CPU1_SA_DQS_DN<2>")
	)
	(segment
		(start 64.15786 -293.79164)
		(end 64.007746 -293.756842)
		(width 0.1016)
		(layer "F.Cu")
		(net "M_A_CPU1_SA_DQS_DN<2>")
	)
	(segment
		(start 84.836762 -272.997168)
		(end 84.67217 -272.997168)
		(width 0.088646)
		(layer "F.Cu")
		(net "M_A_CPU1_SA_DQS_DN<2>")
	)
	(segment
		(start 70.32244 -294.189404)
		(end 70.19798 -294.313864)
		(width 0.20066)
		(layer "F.Cu")
		(net "M_A_CPU1_SA_DQS_DN<2>")
	)
	(segment
		(start 56.379872 -293.780972)
		(end 56.39054 -293.79164)
		(width 0.1016)
		(layer "F.Cu")
		(net "M_A_CPU1_SA_DQS_DN<2>")
	)
	(segment
		(start 67.29222 -294.313864)
		(end 66.69024 -294.313864)
		(width 0.20066)
		(layer "F.Cu")
		(net "M_A_CPU1_SA_DQS_DN<2>")
	)
	(segment
		(start 63.951612 -293.756842)
		(end 63.61684 -293.756842)
		(width 0.20066)
		(layer "F.Cu")
		(net "M_A_CPU1_SA_DQS_DN<2>")
	)
	(segment
		(start 83.444842 -274.281646)
		(end 80.781652 -276.944836)
		(width 0.1524)
		(layer "F.Cu")
		(net "M_A_CPU1_SA_DQS_DN<2>")
	)
	(segment
		(start 72.419718 -294.189404)
		(end 71.817738 -294.189404)
		(width 0.20066)
		(layer "F.Cu")
		(net "M_A_CPU1_SA_DQS_DN<2>")
	)
	(segment
		(start 79.21498 -291.003482)
		(end 79.188056 -291.030406)
		(width 0.1524)
		(layer "F.Cu")
		(net "M_A_CPU1_SA_DQS_DN<2>")
	)
	(segment
		(start 66.595244 -294.02786)
		(end 66.359024 -293.79164)
		(width 0.20066)
		(layer "F.Cu")
		(net "M_A_CPU1_SA_DQS_DN<2>")
	)
	(segment
		(start 54.765702 -293.62781)
		(end 55.401718 -294.053006)
		(width 0.20066)
		(layer "F.Cu")
		(net "M_A_CPU1_SA_DQS_DN<2>")
	)
	(segment
		(start 83.85302 -273.87296)
		(end 83.64601 -274.125182)
		(width 0.088646)
		(layer "F.Cu")
		(net "M_A_CPU1_SA_DQS_DN<2>")
	)
	(segment
		(start 59.841384 -293.62781)
		(end 60.139326 -293.62781)
		(width 0.20066)
		(layer "F.Cu")
		(net "M_A_CPU1_SA_DQS_DN<2>")
	)
	(segment
		(start 59.036966 -293.782242)
		(end 59.30773 -294.053006)
		(width 0.20066)
		(layer "F.Cu")
		(net "M_A_CPU1_SA_DQS_DN<2>")
	)
	(segment
		(start 79.432912 -290.837366)
		(end 79.266796 -291.003482)
		(width 0.1524)
		(layer "F.Cu")
		(net "M_A_CPU1_SA_DQS_DN<2>")
	)
	(segment
		(start 75.207622 -294.036496)
		(end 74.537824 -294.313864)
		(width 0.20066)
		(layer "F.Cu")
		(net "M_A_CPU1_SA_DQS_DN<2>")
	)
	(segment
		(start 56.39054 -293.79164)
		(end 58.694828 -293.79164)
		(width 0.1016)
		(layer "F.Cu")
		(net "M_A_CPU1_SA_DQS_DN<2>")
	)
	(segment
		(start 78.160626 -291.881814)
		(end 78.160626 -292.057836)
		(width 0.20066)
		(layer "F.Cu")
		(net "M_A_CPU1_SA_DQS_DN<2>")
	)
	(segment
		(start 63.61684 -293.756842)
		(end 63.545212 -293.82847)
		(width 0.20066)
		(layer "F.Cu")
		(net "M_A_CPU1_SA_DQS_DN<2>")
	)
	(segment
		(start 58.704226 -293.782242)
		(end 59.036966 -293.782242)
		(width 0.20066)
		(layer "F.Cu")
		(net "M_A_CPU1_SA_DQS_DN<2>")
	)
	(segment
		(start 85.265768 -272.747232)
		(end 85.086698 -272.747232)
		(width 0.088646)
		(layer "F.Cu")
		(net "M_A_CPU1_SA_DQS_DN<2>")
	)
	(segment
		(start 55.401718 -294.053006)
		(end 55.710328 -294.053006)
		(width 0.20066)
		(layer "F.Cu")
		(net "M_A_CPU1_SA_DQS_DN<2>")
	)
	(segment
		(start 56.37911 -293.780972)
		(end 56.379872 -293.780972)
		(width 0.1016)
		(layer "F.Cu")
		(net "M_A_CPU1_SA_DQS_DN<2>")
	)
	(segment
		(start 75.831446 -293.643304)
		(end 75.274932 -293.873936)
		(width 0.20066)
		(layer "F.Cu")
		(net "M_A_CPU1_SA_DQS_DN<2>")
	)
	(segment
		(start 77.133196 -292.909244)
		(end 77.133196 -293.08552)
		(width 0.20066)
		(layer "F.Cu")
		(net "M_A_CPU1_SA_DQS_DN<2>")
	)
	(segment
		(start 68.01866 -294.189404)
		(end 67.41668 -294.189404)
		(width 0.20066)
		(layer "F.Cu")
		(net "M_A_CPU1_SA_DQS_DN<2>")
	)
	(segment
		(start 84.423758 -273.100038)
		(end 84.260436 -273.263614)
		(width 0.088646)
		(layer "F.Cu")
		(net "M_A_CPU1_SA_DQS_DN<2>")
	)
	(segment
		(start 58.694828 -293.79164)
		(end 58.704226 -293.782242)
		(width 0.1016)
		(layer "F.Cu")
		(net "M_A_CPU1_SA_DQS_DN<2>")
	)
	(segment
		(start 85.086698 -272.747232)
		(end 84.836762 -272.997168)
		(width 0.088646)
		(layer "F.Cu")
		(net "M_A_CPU1_SA_DQS_DN<2>")
	)
	(segment
		(start 71.693278 -294.313864)
		(end 71.04888 -294.313864)
		(width 0.20066)
		(layer "F.Cu")
		(net "M_A_CPU1_SA_DQS_DN<2>")
	)
	(segment
		(start 63.464186 -294.117014)
		(end 63.148972 -294.117014)
		(width 0.20066)
		(layer "F.Cu")
		(net "M_A_CPU1_SA_DQS_DN<2>")
	)
	(segment
		(start 66.69024 -294.313864)
		(end 66.595244 -294.218868)
		(width 0.20066)
		(layer "F.Cu")
		(net "M_A_CPU1_SA_DQS_DN<2>")
	)
	(segment
		(start 70.19798 -294.313864)
		(end 69.596 -294.313864)
		(width 0.20066)
		(layer "F.Cu")
		(net "M_A_CPU1_SA_DQS_DN<2>")
	)
	(segment
		(start 55.982362 -293.780972)
		(end 56.37911 -293.780972)
		(width 0.20066)
		(layer "F.Cu")
		(net "M_A_CPU1_SA_DQS_DN<2>")
	)
	(segment
		(start 54.212998 -293.62781)
		(end 54.765702 -293.62781)
		(width 0.20066)
		(layer "F.Cu")
		(net "M_A_CPU1_SA_DQS_DN<2>")
	)
	(segment
		(start 59.416188 -294.053006)
		(end 59.841384 -293.62781)
		(width 0.20066)
		(layer "F.Cu")
		(net "M_A_CPU1_SA_DQS_DN<2>")
	)
	(segment
		(start 63.545212 -293.82847)
		(end 63.545212 -294.035988)
		(width 0.20066)
		(layer "F.Cu")
		(net "M_A_CPU1_SA_DQS_DN<2>")
	)
	(segment
		(start 61.942726 -293.617396)
		(end 61.692536 -293.617396)
		(width 0.20066)
		(layer "F.Cu")
		(net "M_A_CPU1_SA_DQS_DN<2>")
	)
	(segment
		(start 85.435694 -272.917158)
		(end 85.265768 -272.747232)
		(width 0.088646)
		(layer "F.Cu")
		(net "M_A_CPU1_SA_DQS_DN<2>")
	)
	(segment
		(start 75.994006 -293.710614)
		(end 75.831446 -293.643304)
		(width 0.20066)
		(layer "F.Cu")
		(net "M_A_CPU1_SA_DQS_DN<2>")
	)
	(segment
		(start 68.14312 -294.313864)
		(end 68.01866 -294.189404)
		(width 0.20066)
		(layer "F.Cu")
		(net "M_A_CPU1_SA_DQS_DN<2>")
	)
	(segment
		(start 73.270618 -294.189404)
		(end 73.146158 -294.313864)
		(width 0.20066)
		(layer "F.Cu")
		(net "M_A_CPU1_SA_DQS_DN<2>")
	)
	(segment
		(start 64.007746 -293.756842)
		(end 63.951612 -293.756842)
		(width 0.1016)
		(layer "F.Cu")
		(net "M_A_CPU1_SA_DQS_DN<2>")
	)
	(segment
		(start 67.41668 -294.189404)
		(end 67.29222 -294.313864)
		(width 0.20066)
		(layer "F.Cu")
		(net "M_A_CPU1_SA_DQS_DN<2>")
	)
	(segment
		(start 61.44133 -293.366698)
		(end 60.947046 -293.366698)
		(width 0.20066)
		(layer "F.Cu")
		(net "M_A_CPU1_SA_DQS_DN<2>")
	)
	(segment
		(start 75.274932 -293.873936)
		(end 75.207622 -294.036496)
		(width 0.20066)
		(layer "F.Cu")
		(net "M_A_CPU1_SA_DQS_DN<2>")
	)
	(segment
		(start 80.123792 -278.176736)
		(end 79.432912 -281.63139)
		(width 0.1524)
		(layer "F.Cu")
		(net "M_A_CPU1_SA_DQS_DN<2>")
	)
	(segment
		(start 69.596 -294.313864)
		(end 69.47154 -294.189404)
		(width 0.20066)
		(layer "F.Cu")
		(net "M_A_CPU1_SA_DQS_DN<2>")
	)
	(segment
		(start 83.64601 -274.125182)
		(end 83.50504 -274.266152)
		(width 0.088646)
		(layer "F.Cu")
		(net "M_A_CPU1_SA_DQS_DN<2>")
	)
	(segment
		(start 79.188056 -291.030406)
		(end 78.762606 -291.455856)
		(width 0.20066)
		(layer "F.Cu")
		(net "M_A_CPU1_SA_DQS_DN<2>")
	)
	(segment
		(start 78.160626 -292.057836)
		(end 77.735176 -292.483286)
		(width 0.20066)
		(layer "F.Cu")
		(net "M_A_CPU1_SA_DQS_DN<2>")
	)
	(segment
		(start 77.133196 -293.08552)
		(end 76.871322 -293.347394)
		(width 0.20066)
		(layer "F.Cu")
		(net "M_A_CPU1_SA_DQS_DN<2>")
	)
	(segment
		(start 84.260436 -273.263614)
		(end 83.85302 -273.87296)
		(width 0.088646)
		(layer "F.Cu")
		(net "M_A_CPU1_SA_DQS_DN<2>")
	)
	(segment
		(start 61.692536 -293.617396)
		(end 61.441584 -293.366444)
		(width 0.20066)
		(layer "F.Cu")
		(net "M_A_CPU1_SA_DQS_DN<2>")
	)
	(segment
		(start 83.50504 -274.266152)
		(end 83.460336 -274.266152)
		(width 0.088646)
		(layer "F.Cu")
		(net "M_A_CPU1_SA_DQS_DN<2>")
	)
	(segment
		(start 72.544178 -294.313864)
		(end 72.419718 -294.189404)
		(width 0.20066)
		(layer "F.Cu")
		(net "M_A_CPU1_SA_DQS_DN<2>")
	)
	(segment
		(start 68.7451 -294.313864)
		(end 68.14312 -294.313864)
		(width 0.20066)
		(layer "F.Cu")
		(net "M_A_CPU1_SA_DQS_DN<2>")
	)
	(segment
		(start 84.67217 -272.997168)
		(end 84.423758 -273.100038)
		(width 0.088646)
		(layer "F.Cu")
		(net "M_A_CPU1_SA_DQS_DN<2>")
	)
	(segment
		(start 59.30773 -294.053006)
		(end 59.416188 -294.053006)
		(width 0.20066)
		(layer "F.Cu")
		(net "M_A_CPU1_SA_DQS_DN<2>")
	)
	(segment
		(start 61.441584 -293.366444)
		(end 61.44133 -293.366698)
		(width 0.20066)
		(layer "F.Cu")
		(net "M_A_CPU1_SA_DQS_DN<2>")
	)
	(segment
		(start 69.47154 -294.189404)
		(end 68.86956 -294.189404)
		(width 0.20066)
		(layer "F.Cu")
		(net "M_A_CPU1_SA_DQS_DN<2>")
	)
	(segment
		(start 83.460336 -274.266152)
		(end 83.444842 -274.281646)
		(width 0.088646)
		(layer "F.Cu")
		(net "M_A_CPU1_SA_DQS_DN<2>")
	)
	(segment
		(start 79.432912 -281.63139)
		(end 79.432912 -290.837366)
		(width 0.1524)
		(layer "F.Cu")
		(net "M_A_CPU1_SA_DQS_DN<2>")
	)
	(segment
		(start 73.872598 -294.189404)
		(end 73.270618 -294.189404)
		(width 0.20066)
		(layer "F.Cu")
		(net "M_A_CPU1_SA_DQS_DN<2>")
	)
	(segment
		(start 60.400438 -293.366698)
		(end 60.947046 -293.366698)
		(width 0.20066)
		(layer "F.Cu")
		(net "M_A_CPU1_SA_DQS_DN<2>")
	)
	(segment
		(start 68.86956 -294.189404)
		(end 68.7451 -294.313864)
		(width 0.20066)
		(layer "F.Cu")
		(net "M_A_CPU1_SA_DQS_DN<2>")
	)
	(segment
		(start 55.710328 -294.053006)
		(end 55.982362 -293.780972)
		(width 0.20066)
		(layer "F.Cu")
		(net "M_A_CPU1_SA_DQS_DN<2>")
	)
	(segment
		(start 78.586584 -291.455856)
		(end 78.160626 -291.881814)
		(width 0.20066)
		(layer "F.Cu")
		(net "M_A_CPU1_SA_DQS_DN<2>")
	)
	(segment
		(start 66.237612 -293.79164)
		(end 64.15786 -293.79164)
		(width 0.1016)
		(layer "F.Cu")
		(net "M_A_CPU1_SA_DQS_DN<2>")
	)
	(segment
		(start 77.735176 -292.483286)
		(end 77.559154 -292.483286)
		(width 0.20066)
		(layer "F.Cu")
		(net "M_A_CPU1_SA_DQS_DN<2>")
	)
	(segment
		(start 88.255094 -269.66164)
		(end 88.255094 -270.19758)
		(width 0.20066)
		(layer "F.Cu")
		(net "M_A_CPU1_SA_DQS_DN<1>")
	)
	(segment
		(start 55.90286 -303.403)
		(end 55.362856 -303.403)
		(width 0.20066)
		(layer "F.Cu")
		(net "M_A_CPU1_SA_DQS_DN<1>")
	)
	(segment
		(start 58.704226 -303.141634)
		(end 56.39054 -303.141634)
		(width 0.1016)
		(layer "F.Cu")
		(net "M_A_CPU1_SA_DQS_DN<1>")
	)
	(segment
		(start 54.72684 -302.977804)
		(end 54.212998 -302.977804)
		(width 0.20066)
		(layer "F.Cu")
		(net "M_A_CPU1_SA_DQS_DN<1>")
	)
	(segment
		(start 59.307476 -303.403)
		(end 59.120786 -303.403)
		(width 0.20066)
		(layer "F.Cu")
		(net "M_A_CPU1_SA_DQS_DN<1>")
	)
	(segment
		(start 56.37911 -303.130966)
		(end 56.174894 -303.130966)
		(width 0.20066)
		(layer "F.Cu")
		(net "M_A_CPU1_SA_DQS_DN<1>")
	)
	(segment
		(start 56.174894 -303.130966)
		(end 55.90286 -303.403)
		(width 0.20066)
		(layer "F.Cu")
		(net "M_A_CPU1_SA_DQS_DN<1>")
	)
	(segment
		(start 56.39054 -303.141634)
		(end 56.379872 -303.130966)
		(width 0.101854)
		(layer "F.Cu")
		(net "M_A_CPU1_SA_DQS_DN<1>")
	)
	(segment
		(start 62.051946 -302.716692)
		(end 60.947046 -302.716692)
		(width 0.20066)
		(layer "F.Cu")
		(net "M_A_CPU1_SA_DQS_DN<1>")
	)
	(segment
		(start 56.379872 -303.130966)
		(end 56.37911 -303.130966)
		(width 0.101854)
		(layer "F.Cu")
		(net "M_A_CPU1_SA_DQS_DN<1>")
	)
	(segment
		(start 60.400438 -302.716692)
		(end 60.139326 -302.977804)
		(width 0.20066)
		(layer "F.Cu")
		(net "M_A_CPU1_SA_DQS_DN<1>")
	)
	(segment
		(start 60.139326 -302.977804)
		(end 59.732672 -302.977804)
		(width 0.20066)
		(layer "F.Cu")
		(net "M_A_CPU1_SA_DQS_DN<1>")
	)
	(segment
		(start 60.947046 -302.716692)
		(end 60.400438 -302.716692)
		(width 0.20066)
		(layer "F.Cu")
		(net "M_A_CPU1_SA_DQS_DN<1>")
	)
	(segment
		(start 54.212998 -302.977804)
		(end 53.951886 -302.716692)
		(width 0.20066)
		(layer "F.Cu")
		(net "M_A_CPU1_SA_DQS_DN<1>")
	)
	(segment
		(start 53.951886 -302.716692)
		(end 53.403246 -302.716692)
		(width 0.20066)
		(layer "F.Cu")
		(net "M_A_CPU1_SA_DQS_DN<1>")
	)
	(segment
		(start 55.362856 -303.403)
		(end 54.72684 -302.977804)
		(width 0.20066)
		(layer "F.Cu")
		(net "M_A_CPU1_SA_DQS_DN<1>")
	)
	(segment
		(start 58.85942 -303.141634)
		(end 58.704226 -303.141634)
		(width 0.20066)
		(layer "F.Cu")
		(net "M_A_CPU1_SA_DQS_DN<1>")
	)
	(segment
		(start 59.120786 -303.403)
		(end 58.85942 -303.141634)
		(width 0.20066)
		(layer "F.Cu")
		(net "M_A_CPU1_SA_DQS_DN<1>")
	)
	(segment
		(start 59.732672 -302.977804)
		(end 59.307476 -303.403)
		(width 0.20066)
		(layer "F.Cu")
		(net "M_A_CPU1_SA_DQS_DN<1>")
	)
	(segment
		(start 87.691214 -270.41348)
		(end 87.503 -270.522192)
		(width 0.088646)
		(layer "In2.Cu")
		(net "M_A_CPU1_SA_DQS_DN<1>")
	)
	(segment
		(start 64.332866 -303.132744)
		(end 64.133222 -302.9331)
		(width 0.16002)
		(layer "In2.Cu")
		(net "M_A_CPU1_SA_DQS_DN<1>")
	)
	(segment
		(start 87.127842 -270.522192)
		(end 87.127588 -270.522192)
		(width 0.088646)
		(layer "In2.Cu")
		(net "M_A_CPU1_SA_DQS_DN<1>")
	)
	(segment
		(start 68.618354 -299.29836)
		(end 68.493894 -299.42282)
		(width 0.18288)
		(layer "In2.Cu")
		(net "M_A_CPU1_SA_DQS_DN<1>")
	)
	(segment
		(start 86.077044 -270.980154)
		(end 85.135974 -270.980154)
		(width 0.088646)
		(layer "In2.Cu")
		(net "M_A_CPU1_SA_DQS_DN<1>")
	)
	(segment
		(start 68.493894 -298.62526)
		(end 68.618354 -298.74972)
		(width 0.18288)
		(layer "In2.Cu")
		(net "M_A_CPU1_SA_DQS_DN<1>")
	)
	(segment
		(start 71.124572 -291.524436)
		(end 70.961758 -291.591746)
		(width 0.18288)
		(layer "In2.Cu")
		(net "M_A_CPU1_SA_DQS_DN<1>")
	)
	(segment
		(start 70.961758 -291.591746)
		(end 70.7517 -292.09873)
		(width 0.18288)
		(layer "In2.Cu")
		(net "M_A_CPU1_SA_DQS_DN<1>")
	)
	(segment
		(start 64.133222 -302.916844)
		(end 64.105028 -302.88865)
		(width 0.16002)
		(layer "In2.Cu")
		(net "M_A_CPU1_SA_DQS_DN<1>")
	)
	(segment
		(start 66.787014 -303.409858)
		(end 66.602864 -303.409858)
		(width 0.18288)
		(layer "In2.Cu")
		(net "M_A_CPU1_SA_DQS_DN<1>")
	)
	(segment
		(start 70.30339 -293.505382)
		(end 70.093332 -294.012112)
		(width 0.18288)
		(layer "In2.Cu")
		(net "M_A_CPU1_SA_DQS_DN<1>")
	)
	(segment
		(start 82.484722 -273.546824)
		(end 81.211166 -276.625304)
		(width 0.18288)
		(layer "In2.Cu")
		(net "M_A_CPU1_SA_DQS_DN<1>")
	)
	(segment
		(start 71.26732 -290.854892)
		(end 71.33463 -291.017706)
		(width 0.18288)
		(layer "In2.Cu")
		(net "M_A_CPU1_SA_DQS_DN<1>")
	)
	(segment
		(start 77.154786 -280.771854)
		(end 77.065886 -280.986484)
		(width 0.18288)
		(layer "In2.Cu")
		(net "M_A_CPU1_SA_DQS_DN<1>")
	)
	(segment
		(start 70.7517 -292.09873)
		(end 70.81901 -292.261544)
		(width 0.18288)
		(layer "In2.Cu")
		(net "M_A_CPU1_SA_DQS_DN<1>")
	)
	(segment
		(start 68.618354 -298.74972)
		(end 68.618354 -299.29836)
		(width 0.18288)
		(layer "In2.Cu")
		(net "M_A_CPU1_SA_DQS_DN<1>")
	)
	(segment
		(start 68.618354 -300.301152)
		(end 67.714876 -302.481742)
		(width 0.18288)
		(layer "In2.Cu")
		(net "M_A_CPU1_SA_DQS_DN<1>")
	)
	(segment
		(start 72.155812 -289.03676)
		(end 71.992998 -289.10407)
		(width 0.18288)
		(layer "In2.Cu")
		(net "M_A_CPU1_SA_DQS_DN<1>")
	)
	(segment
		(start 84.624418 -271.406874)
		(end 82.484722 -273.546824)
		(width 0.18288)
		(layer "In2.Cu")
		(net "M_A_CPU1_SA_DQS_DN<1>")
	)
	(segment
		(start 73.024238 -286.616394)
		(end 72.81418 -287.123378)
		(width 0.18288)
		(layer "In2.Cu")
		(net "M_A_CPU1_SA_DQS_DN<1>")
	)
	(segment
		(start 69.930518 -294.079422)
		(end 69.72046 -294.586406)
		(width 0.18288)
		(layer "In2.Cu")
		(net "M_A_CPU1_SA_DQS_DN<1>")
	)
	(segment
		(start 69.78777 -294.74922)
		(end 68.618354 -297.570652)
		(width 0.18288)
		(layer "In2.Cu")
		(net "M_A_CPU1_SA_DQS_DN<1>")
	)
	(segment
		(start 73.39711 -286.042354)
		(end 73.187052 -286.549084)
		(width 0.18288)
		(layer "In2.Cu")
		(net "M_A_CPU1_SA_DQS_DN<1>")
	)
	(segment
		(start 65.9511 -303.141634)
		(end 65.697354 -303.39538)
		(width 0.18288)
		(layer "In2.Cu")
		(net "M_A_CPU1_SA_DQS_DN<1>")
	)
	(segment
		(start 85.135974 -270.980154)
		(end 84.969604 -271.146524)
		(width 0.088646)
		(layer "In2.Cu")
		(net "M_A_CPU1_SA_DQS_DN<1>")
	)
	(segment
		(start 71.78294 -289.611054)
		(end 71.85025 -289.773868)
		(width 0.18288)
		(layer "In2.Cu")
		(net "M_A_CPU1_SA_DQS_DN<1>")
	)
	(segment
		(start 71.33463 -291.017706)
		(end 71.124572 -291.524436)
		(width 0.18288)
		(layer "In2.Cu")
		(net "M_A_CPU1_SA_DQS_DN<1>")
	)
	(segment
		(start 72.671432 -287.792922)
		(end 72.508618 -287.860232)
		(width 0.18288)
		(layer "In2.Cu")
		(net "M_A_CPU1_SA_DQS_DN<1>")
	)
	(segment
		(start 64.708278 -303.39538)
		(end 64.543686 -303.327054)
		(width 0.18288)
		(layer "In2.Cu")
		(net "M_A_CPU1_SA_DQS_DN<1>")
	)
	(segment
		(start 77.154278 -280.771092)
		(end 77.154786 -280.771854)
		(width 0.18288)
		(layer "In2.Cu")
		(net "M_A_CPU1_SA_DQS_DN<1>")
	)
	(segment
		(start 72.29856 -288.367216)
		(end 72.36587 -288.53003)
		(width 0.18288)
		(layer "In2.Cu")
		(net "M_A_CPU1_SA_DQS_DN<1>")
	)
	(segment
		(start 62.582552 -303.004474)
		(end 62.339728 -303.004474)
		(width 0.18288)
		(layer "In2.Cu")
		(net "M_A_CPU1_SA_DQS_DN<1>")
	)
	(segment
		(start 71.85025 -289.773868)
		(end 71.640192 -290.280598)
		(width 0.18288)
		(layer "In2.Cu")
		(net "M_A_CPU1_SA_DQS_DN<1>")
	)
	(segment
		(start 72.36587 -288.53003)
		(end 72.155812 -289.03676)
		(width 0.18288)
		(layer "In2.Cu")
		(net "M_A_CPU1_SA_DQS_DN<1>")
	)
	(segment
		(start 66.602864 -303.409858)
		(end 66.33464 -303.141634)
		(width 0.18288)
		(layer "In2.Cu")
		(net "M_A_CPU1_SA_DQS_DN<1>")
	)
	(segment
		(start 72.508618 -287.860232)
		(end 72.29856 -288.367216)
		(width 0.18288)
		(layer "In2.Cu")
		(net "M_A_CPU1_SA_DQS_DN<1>")
	)
	(segment
		(start 65.697354 -303.39538)
		(end 64.708278 -303.39538)
		(width 0.18288)
		(layer "In2.Cu")
		(net "M_A_CPU1_SA_DQS_DN<1>")
	)
	(segment
		(start 64.543686 -303.327054)
		(end 64.377316 -303.160938)
		(width 0.18288)
		(layer "In2.Cu")
		(net "M_A_CPU1_SA_DQS_DN<1>")
	)
	(segment
		(start 64.349122 -303.132744)
		(end 64.332866 -303.132744)
		(width 0.16002)
		(layer "In2.Cu")
		(net "M_A_CPU1_SA_DQS_DN<1>")
	)
	(segment
		(start 69.72046 -294.586406)
		(end 69.78777 -294.74922)
		(width 0.18288)
		(layer "In2.Cu")
		(net "M_A_CPU1_SA_DQS_DN<1>")
	)
	(segment
		(start 72.88149 -287.286192)
		(end 72.671432 -287.792922)
		(width 0.18288)
		(layer "In2.Cu")
		(net "M_A_CPU1_SA_DQS_DN<1>")
	)
	(segment
		(start 70.446138 -292.835584)
		(end 70.23608 -293.342568)
		(width 0.18288)
		(layer "In2.Cu")
		(net "M_A_CPU1_SA_DQS_DN<1>")
	)
	(segment
		(start 64.105028 -302.88865)
		(end 63.853568 -302.63719)
		(width 0.18288)
		(layer "In2.Cu")
		(net "M_A_CPU1_SA_DQS_DN<1>")
	)
	(segment
		(start 86.445852 -270.611092)
		(end 86.077044 -270.980154)
		(width 0.088646)
		(layer "In2.Cu")
		(net "M_A_CPU1_SA_DQS_DN<1>")
	)
	(segment
		(start 68.618354 -300.09592)
		(end 68.618354 -300.301152)
		(width 0.18288)
		(layer "In2.Cu")
		(net "M_A_CPU1_SA_DQS_DN<1>")
	)
	(segment
		(start 84.884768 -271.146524)
		(end 84.624418 -271.406874)
		(width 0.18288)
		(layer "In2.Cu")
		(net "M_A_CPU1_SA_DQS_DN<1>")
	)
	(segment
		(start 88.255094 -270.19758)
		(end 88.039194 -270.41348)
		(width 0.088646)
		(layer "In2.Cu")
		(net "M_A_CPU1_SA_DQS_DN<1>")
	)
	(segment
		(start 88.039194 -270.41348)
		(end 87.691214 -270.41348)
		(width 0.088646)
		(layer "In2.Cu")
		(net "M_A_CPU1_SA_DQS_DN<1>")
	)
	(segment
		(start 71.477378 -290.347908)
		(end 71.26732 -290.854892)
		(width 0.18288)
		(layer "In2.Cu")
		(net "M_A_CPU1_SA_DQS_DN<1>")
	)
	(segment
		(start 81.211166 -276.625304)
		(end 77.217778 -280.618692)
		(width 0.18288)
		(layer "In2.Cu")
		(net "M_A_CPU1_SA_DQS_DN<1>")
	)
	(segment
		(start 84.969604 -271.146524)
		(end 84.884768 -271.146524)
		(width 0.088646)
		(layer "In2.Cu")
		(net "M_A_CPU1_SA_DQS_DN<1>")
	)
	(segment
		(start 68.493894 -298.07662)
		(end 68.493894 -298.62526)
		(width 0.18288)
		(layer "In2.Cu")
		(net "M_A_CPU1_SA_DQS_DN<1>")
	)
	(segment
		(start 67.714876 -302.481742)
		(end 66.787014 -303.409858)
		(width 0.18288)
		(layer "In2.Cu")
		(net "M_A_CPU1_SA_DQS_DN<1>")
	)
	(segment
		(start 66.33464 -303.141634)
		(end 65.9511 -303.141634)
		(width 0.18288)
		(layer "In2.Cu")
		(net "M_A_CPU1_SA_DQS_DN<1>")
	)
	(segment
		(start 76.083668 -283.355796)
		(end 73.39711 -286.042354)
		(width 0.18288)
		(layer "In2.Cu")
		(net "M_A_CPU1_SA_DQS_DN<1>")
	)
	(segment
		(start 62.339728 -303.004474)
		(end 62.051946 -302.716692)
		(width 0.18288)
		(layer "In2.Cu")
		(net "M_A_CPU1_SA_DQS_DN<1>")
	)
	(segment
		(start 70.093332 -294.012112)
		(end 69.930518 -294.079422)
		(width 0.18288)
		(layer "In2.Cu")
		(net "M_A_CPU1_SA_DQS_DN<1>")
	)
	(segment
		(start 77.217778 -280.618692)
		(end 77.154278 -280.771092)
		(width 0.18288)
		(layer "In2.Cu")
		(net "M_A_CPU1_SA_DQS_DN<1>")
	)
	(segment
		(start 72.81418 -287.123378)
		(end 72.88149 -287.286192)
		(width 0.18288)
		(layer "In2.Cu")
		(net "M_A_CPU1_SA_DQS_DN<1>")
	)
	(segment
		(start 64.377316 -303.160938)
		(end 64.349122 -303.132744)
		(width 0.16002)
		(layer "In2.Cu")
		(net "M_A_CPU1_SA_DQS_DN<1>")
	)
	(segment
		(start 71.992998 -289.10407)
		(end 71.78294 -289.611054)
		(width 0.18288)
		(layer "In2.Cu")
		(net "M_A_CPU1_SA_DQS_DN<1>")
	)
	(segment
		(start 71.640192 -290.280598)
		(end 71.477378 -290.347908)
		(width 0.18288)
		(layer "In2.Cu")
		(net "M_A_CPU1_SA_DQS_DN<1>")
	)
	(segment
		(start 70.23608 -293.342568)
		(end 70.30339 -293.505382)
		(width 0.18288)
		(layer "In2.Cu")
		(net "M_A_CPU1_SA_DQS_DN<1>")
	)
	(segment
		(start 68.618354 -297.95216)
		(end 68.493894 -298.07662)
		(width 0.18288)
		(layer "In2.Cu")
		(net "M_A_CPU1_SA_DQS_DN<1>")
	)
	(segment
		(start 77.065886 -280.986484)
		(end 76.083668 -283.355796)
		(width 0.18288)
		(layer "In2.Cu")
		(net "M_A_CPU1_SA_DQS_DN<1>")
	)
	(segment
		(start 68.493894 -299.97146)
		(end 68.618354 -300.09592)
		(width 0.18288)
		(layer "In2.Cu")
		(net "M_A_CPU1_SA_DQS_DN<1>")
	)
	(segment
		(start 64.133222 -302.9331)
		(end 64.133222 -302.916844)
		(width 0.16002)
		(layer "In2.Cu")
		(net "M_A_CPU1_SA_DQS_DN<1>")
	)
	(segment
		(start 70.81901 -292.261544)
		(end 70.608952 -292.768274)
		(width 0.18288)
		(layer "In2.Cu")
		(net "M_A_CPU1_SA_DQS_DN<1>")
	)
	(segment
		(start 62.949836 -302.63719)
		(end 62.582552 -303.004474)
		(width 0.18288)
		(layer "In2.Cu")
		(net "M_A_CPU1_SA_DQS_DN<1>")
	)
	(segment
		(start 70.608952 -292.768274)
		(end 70.446138 -292.835584)
		(width 0.18288)
		(layer "In2.Cu")
		(net "M_A_CPU1_SA_DQS_DN<1>")
	)
	(segment
		(start 68.618354 -297.570652)
		(end 68.618354 -297.95216)
		(width 0.18288)
		(layer "In2.Cu")
		(net "M_A_CPU1_SA_DQS_DN<1>")
	)
	(segment
		(start 63.853568 -302.63719)
		(end 62.949836 -302.63719)
		(width 0.18288)
		(layer "In2.Cu")
		(net "M_A_CPU1_SA_DQS_DN<1>")
	)
	(segment
		(start 68.493894 -299.42282)
		(end 68.493894 -299.97146)
		(width 0.18288)
		(layer "In2.Cu")
		(net "M_A_CPU1_SA_DQS_DN<1>")
	)
	(segment
		(start 73.187052 -286.549084)
		(end 73.024238 -286.616394)
		(width 0.18288)
		(layer "In2.Cu")
		(net "M_A_CPU1_SA_DQS_DN<1>")
	)
	(arc
		(start 86.563454 -270.521938)
		(mid 86.50172 -270.562648)
		(end 86.445852 -270.611092)
		(width 0.088646)
		(layer "In2.Cu")
		(net "M_A_CPU1_SA_DQS_DN<1>")
	)
	(arc
		(start 87.127588 -270.522192)
		(mid 86.845567 -270.446636)
		(end 86.563454 -270.521938)
		(width 0.088646)
		(layer "In2.Cu")
		(net "M_A_CPU1_SA_DQS_DN<1>")
	)
	(arc
		(start 87.503 -270.522192)
		(mid 87.315438 -270.572428)
		(end 87.127842 -270.522192)
		(width 0.088646)
		(layer "In2.Cu")
		(net "M_A_CPU1_SA_DQS_DN<1>")
	)
	(segment
		(start 56.379872 -312.48096)
		(end 56.39054 -312.491628)
		(width 0.1016)
		(layer "F.Cu")
		(net "M_A_CPU1_SA_DQS_DN<0>")
	)
	(segment
		(start 83.889088 -279.671018)
		(end 83.344512 -282.393898)
		(width 0.1524)
		(layer "F.Cu")
		(net "M_A_CPU1_SA_DQS_DN<0>")
	)
	(segment
		(start 63.533782 -312.485786)
		(end 63.256922 -312.762646)
		(width 0.20066)
		(layer "F.Cu")
		(net "M_A_CPU1_SA_DQS_DN<0>")
	)
	(segment
		(start 63.008256 -312.762646)
		(end 61.98235 -312.337704)
		(width 0.20066)
		(layer "F.Cu")
		(net "M_A_CPU1_SA_DQS_DN<0>")
	)
	(segment
		(start 66.63817 -312.483246)
		(end 66.186812 -312.483246)
		(width 0.20066)
		(layer "F.Cu")
		(net "M_A_CPU1_SA_DQS_DN<0>")
	)
	(segment
		(start 60.139326 -312.327798)
		(end 60.400438 -312.066686)
		(width 0.20066)
		(layer "F.Cu")
		(net "M_A_CPU1_SA_DQS_DN<0>")
	)
	(segment
		(start 64.043306 -312.485786)
		(end 64.002412 -312.485786)
		(width 0.1016)
		(layer "F.Cu")
		(net "M_A_CPU1_SA_DQS_DN<0>")
	)
	(segment
		(start 84.610956 -278.59482)
		(end 84.610956 -278.864822)
		(width 0.088646)
		(layer "F.Cu")
		(net "M_A_CPU1_SA_DQS_DN<0>")
	)
	(segment
		(start 83.344512 -296.159936)
		(end 83.13039 -297.236134)
		(width 0.1524)
		(layer "F.Cu")
		(net "M_A_CPU1_SA_DQS_DN<0>")
	)
	(segment
		(start 55.710328 -312.752994)
		(end 55.982362 -312.48096)
		(width 0.20066)
		(layer "F.Cu")
		(net "M_A_CPU1_SA_DQS_DN<0>")
	)
	(segment
		(start 84.610956 -278.864822)
		(end 84.5185 -279.086818)
		(width 0.088646)
		(layer "F.Cu")
		(net "M_A_CPU1_SA_DQS_DN<0>")
	)
	(segment
		(start 69.964808 -309.724044)
		(end 69.964808 -309.900066)
		(width 0.20066)
		(layer "F.Cu")
		(net "M_A_CPU1_SA_DQS_DN<0>")
	)
	(segment
		(start 66.186812 -312.483246)
		(end 66.171318 -312.483246)
		(width 0.1016)
		(layer "F.Cu")
		(net "M_A_CPU1_SA_DQS_DN<0>")
	)
	(segment
		(start 59.841384 -312.327798)
		(end 60.139326 -312.327798)
		(width 0.20066)
		(layer "F.Cu")
		(net "M_A_CPU1_SA_DQS_DN<0>")
	)
	(segment
		(start 68.335906 -311.352946)
		(end 67.910202 -311.77865)
		(width 0.20066)
		(layer "F.Cu")
		(net "M_A_CPU1_SA_DQS_DN<0>")
	)
	(segment
		(start 82.512408 -298.113704)
		(end 76.477114 -304.148998)
		(width 0.20066)
		(layer "F.Cu")
		(net "M_A_CPU1_SA_DQS_DN<0>")
	)
	(segment
		(start 69.539358 -310.325516)
		(end 69.363336 -310.325516)
		(width 0.20066)
		(layer "F.Cu")
		(net "M_A_CPU1_SA_DQS_DN<0>")
	)
	(segment
		(start 53.403246 -312.066686)
		(end 53.951886 -312.066686)
		(width 0.20066)
		(layer "F.Cu")
		(net "M_A_CPU1_SA_DQS_DN<0>")
	)
	(segment
		(start 61.98235 -312.337704)
		(end 61.712856 -312.337704)
		(width 0.20066)
		(layer "F.Cu")
		(net "M_A_CPU1_SA_DQS_DN<0>")
	)
	(segment
		(start 60.400438 -312.066686)
		(end 60.947046 -312.066686)
		(width 0.20066)
		(layer "F.Cu")
		(net "M_A_CPU1_SA_DQS_DN<0>")
	)
	(segment
		(start 83.13039 -297.236134)
		(end 83.129882 -297.237658)
		(width 0.1524)
		(layer "F.Cu")
		(net "M_A_CPU1_SA_DQS_DN<0>")
	)
	(segment
		(start 67.043808 -312.732674)
		(end 66.887598 -312.732674)
		(width 0.20066)
		(layer "F.Cu")
		(net "M_A_CPU1_SA_DQS_DN<0>")
	)
	(segment
		(start 84.5185 -279.086818)
		(end 84.263484 -279.341834)
		(width 0.088646)
		(layer "F.Cu")
		(net "M_A_CPU1_SA_DQS_DN<0>")
	)
	(segment
		(start 66.171318 -312.483246)
		(end 66.162936 -312.491628)
		(width 0.1016)
		(layer "F.Cu")
		(net "M_A_CPU1_SA_DQS_DN<0>")
	)
	(segment
		(start 69.964808 -309.900066)
		(end 69.539358 -310.325516)
		(width 0.20066)
		(layer "F.Cu")
		(net "M_A_CPU1_SA_DQS_DN<0>")
	)
	(segment
		(start 84.202778 -279.357328)
		(end 83.889088 -279.671018)
		(width 0.1524)
		(layer "F.Cu")
		(net "M_A_CPU1_SA_DQS_DN<0>")
	)
	(segment
		(start 55.407052 -312.752994)
		(end 55.710328 -312.752994)
		(width 0.20066)
		(layer "F.Cu")
		(net "M_A_CPU1_SA_DQS_DN<0>")
	)
	(segment
		(start 64.049148 -312.491628)
		(end 64.043306 -312.485786)
		(width 0.1016)
		(layer "F.Cu")
		(net "M_A_CPU1_SA_DQS_DN<0>")
	)
	(segment
		(start 82.916014 -297.762168)
		(end 82.591402 -298.08678)
		(width 0.1524)
		(layer "F.Cu")
		(net "M_A_CPU1_SA_DQS_DN<0>")
	)
	(segment
		(start 70.566788 -309.298086)
		(end 70.390766 -309.298086)
		(width 0.20066)
		(layer "F.Cu")
		(net "M_A_CPU1_SA_DQS_DN<0>")
	)
	(segment
		(start 84.716366 -278.338788)
		(end 84.610956 -278.59482)
		(width 0.088646)
		(layer "F.Cu")
		(net "M_A_CPU1_SA_DQS_DN<0>")
	)
	(segment
		(start 63.256922 -312.762646)
		(end 63.008256 -312.762646)
		(width 0.20066)
		(layer "F.Cu")
		(net "M_A_CPU1_SA_DQS_DN<0>")
	)
	(segment
		(start 61.712856 -312.337704)
		(end 61.441584 -312.066432)
		(width 0.20066)
		(layer "F.Cu")
		(net "M_A_CPU1_SA_DQS_DN<0>")
	)
	(segment
		(start 59.036966 -312.48223)
		(end 59.30773 -312.752994)
		(width 0.20066)
		(layer "F.Cu")
		(net "M_A_CPU1_SA_DQS_DN<0>")
	)
	(segment
		(start 66.887598 -312.732674)
		(end 66.63817 -312.483246)
		(width 0.20066)
		(layer "F.Cu")
		(net "M_A_CPU1_SA_DQS_DN<0>")
	)
	(segment
		(start 56.37911 -312.48096)
		(end 56.379872 -312.48096)
		(width 0.1016)
		(layer "F.Cu")
		(net "M_A_CPU1_SA_DQS_DN<0>")
	)
	(segment
		(start 66.162936 -312.491628)
		(end 64.049148 -312.491628)
		(width 0.1016)
		(layer "F.Cu")
		(net "M_A_CPU1_SA_DQS_DN<0>")
	)
	(segment
		(start 69.363336 -310.325516)
		(end 68.937378 -310.751474)
		(width 0.20066)
		(layer "F.Cu")
		(net "M_A_CPU1_SA_DQS_DN<0>")
	)
	(segment
		(start 58.694828 -312.491628)
		(end 58.704226 -312.48223)
		(width 0.1016)
		(layer "F.Cu")
		(net "M_A_CPU1_SA_DQS_DN<0>")
	)
	(segment
		(start 53.951886 -312.066686)
		(end 54.212998 -312.327798)
		(width 0.20066)
		(layer "F.Cu")
		(net "M_A_CPU1_SA_DQS_DN<0>")
	)
	(segment
		(start 59.30773 -312.752994)
		(end 59.416188 -312.752994)
		(width 0.20066)
		(layer "F.Cu")
		(net "M_A_CPU1_SA_DQS_DN<0>")
	)
	(segment
		(start 68.937378 -310.751474)
		(end 68.937378 -310.927496)
		(width 0.20066)
		(layer "F.Cu")
		(net "M_A_CPU1_SA_DQS_DN<0>")
	)
	(segment
		(start 64.002412 -312.485786)
		(end 63.533782 -312.485786)
		(width 0.20066)
		(layer "F.Cu")
		(net "M_A_CPU1_SA_DQS_DN<0>")
	)
	(segment
		(start 54.771036 -312.327798)
		(end 55.407052 -312.752994)
		(width 0.20066)
		(layer "F.Cu")
		(net "M_A_CPU1_SA_DQS_DN<0>")
	)
	(segment
		(start 61.441584 -312.066432)
		(end 61.44133 -312.066686)
		(width 0.20066)
		(layer "F.Cu")
		(net "M_A_CPU1_SA_DQS_DN<0>")
	)
	(segment
		(start 84.218272 -279.341834)
		(end 84.202778 -279.357328)
		(width 0.088646)
		(layer "F.Cu")
		(net "M_A_CPU1_SA_DQS_DN<0>")
	)
	(segment
		(start 83.129882 -297.237658)
		(end 82.916014 -297.762168)
		(width 0.1524)
		(layer "F.Cu")
		(net "M_A_CPU1_SA_DQS_DN<0>")
	)
	(segment
		(start 72.230234 -307.63464)
		(end 70.566788 -309.298086)
		(width 0.20066)
		(layer "F.Cu")
		(net "M_A_CPU1_SA_DQS_DN<0>")
	)
	(segment
		(start 56.39054 -312.491628)
		(end 58.694828 -312.491628)
		(width 0.1016)
		(layer "F.Cu")
		(net "M_A_CPU1_SA_DQS_DN<0>")
	)
	(segment
		(start 54.212998 -312.327798)
		(end 54.771036 -312.327798)
		(width 0.20066)
		(layer "F.Cu")
		(net "M_A_CPU1_SA_DQS_DN<0>")
	)
	(segment
		(start 84.91728 -278.137874)
		(end 84.716366 -278.338788)
		(width 0.088646)
		(layer "F.Cu")
		(net "M_A_CPU1_SA_DQS_DN<0>")
	)
	(segment
		(start 68.937378 -310.927496)
		(end 68.511928 -311.352946)
		(width 0.20066)
		(layer "F.Cu")
		(net "M_A_CPU1_SA_DQS_DN<0>")
	)
	(segment
		(start 82.539332 -298.08678)
		(end 82.512408 -298.113704)
		(width 0.1524)
		(layer "F.Cu")
		(net "M_A_CPU1_SA_DQS_DN<0>")
	)
	(segment
		(start 70.390766 -309.298086)
		(end 69.964808 -309.724044)
		(width 0.20066)
		(layer "F.Cu")
		(net "M_A_CPU1_SA_DQS_DN<0>")
	)
	(segment
		(start 68.511928 -311.352946)
		(end 68.335906 -311.352946)
		(width 0.20066)
		(layer "F.Cu")
		(net "M_A_CPU1_SA_DQS_DN<0>")
	)
	(segment
		(start 85.558376 -278.137874)
		(end 84.91728 -278.137874)
		(width 0.088646)
		(layer "F.Cu")
		(net "M_A_CPU1_SA_DQS_DN<0>")
	)
	(segment
		(start 55.982362 -312.48096)
		(end 56.37911 -312.48096)
		(width 0.20066)
		(layer "F.Cu")
		(net "M_A_CPU1_SA_DQS_DN<0>")
	)
	(segment
		(start 58.704226 -312.48223)
		(end 59.036966 -312.48223)
		(width 0.20066)
		(layer "F.Cu")
		(net "M_A_CPU1_SA_DQS_DN<0>")
	)
	(segment
		(start 61.44133 -312.066686)
		(end 60.947046 -312.066686)
		(width 0.20066)
		(layer "F.Cu")
		(net "M_A_CPU1_SA_DQS_DN<0>")
	)
	(segment
		(start 85.74659 -277.800562)
		(end 85.805518 -277.85949)
		(width 0.088646)
		(layer "F.Cu")
		(net "M_A_CPU1_SA_DQS_DN<0>")
	)
	(segment
		(start 59.416188 -312.752994)
		(end 59.841384 -312.327798)
		(width 0.20066)
		(layer "F.Cu")
		(net "M_A_CPU1_SA_DQS_DN<0>")
	)
	(segment
		(start 84.263484 -279.341834)
		(end 84.218272 -279.341834)
		(width 0.088646)
		(layer "F.Cu")
		(net "M_A_CPU1_SA_DQS_DN<0>")
	)
	(segment
		(start 83.344512 -282.393898)
		(end 83.344512 -296.159936)
		(width 0.1524)
		(layer "F.Cu")
		(net "M_A_CPU1_SA_DQS_DN<0>")
	)
	(segment
		(start 85.435694 -277.800562)
		(end 85.74659 -277.800562)
		(width 0.088646)
		(layer "F.Cu")
		(net "M_A_CPU1_SA_DQS_DN<0>")
	)
	(segment
		(start 82.591402 -298.08678)
		(end 82.539332 -298.08678)
		(width 0.1524)
		(layer "F.Cu")
		(net "M_A_CPU1_SA_DQS_DN<0>")
	)
	(segment
		(start 67.194684 -312.67019)
		(end 67.043808 -312.732674)
		(width 0.20066)
		(layer "F.Cu")
		(net "M_A_CPU1_SA_DQS_DN<0>")
	)
	(segment
		(start 67.910202 -311.954672)
		(end 67.194684 -312.67019)
		(width 0.20066)
		(layer "F.Cu")
		(net "M_A_CPU1_SA_DQS_DN<0>")
	)
	(segment
		(start 67.910202 -311.77865)
		(end 67.910202 -311.954672)
		(width 0.20066)
		(layer "F.Cu")
		(net "M_A_CPU1_SA_DQS_DN<0>")
	)
	(segment
		(start 76.477114 -304.148998)
		(end 72.230234 -307.63464)
		(width 0.20066)
		(layer "F.Cu")
		(net "M_A_CPU1_SA_DQS_DN<0>")
	)
	(arc
		(start 85.805518 -277.85949)
		(mid 85.750896 -278.002776)
		(end 85.643466 -278.11222)
		(width 0.088646)
		(layer "F.Cu")
		(net "M_A_CPU1_SA_DQS_DN<0>")
	)
	(arc
		(start 85.643466 -278.11222)
		(mid 85.602828 -278.131381)
		(end 85.558376 -278.137874)
		(width 0.088646)
		(layer "F.Cu")
		(net "M_A_CPU1_SA_DQS_DN<0>")
	)
	(segment
		(start 54.897528 -305.284124)
		(end 54.66334 -305.518312)
		(width 0.20066)
		(layer "F.Cu")
		(net "M_A_CPU1_SA_DQ<9>")
	)
	(segment
		(start 54.897528 -305.021996)
		(end 54.897528 -305.284124)
		(width 0.20066)
		(layer "F.Cu")
		(net "M_A_CPU1_SA_DQ<9>")
	)
	(segment
		(start 56.426354 -304.841656)
		(end 56.418226 -304.833528)
		(width 0.101854)
		(layer "F.Cu")
		(net "M_A_CPU1_SA_DQ<9>")
	)
	(segment
		(start 58.643012 -304.841656)
		(end 56.433212 -304.841656)
		(width 0.1016)
		(layer "F.Cu")
		(net "M_A_CPU1_SA_DQ<9>")
	)
	(segment
		(start 59.246262 -305.266598)
		(end 58.82132 -304.841656)
		(width 0.20066)
		(layer "F.Cu")
		(net "M_A_CPU1_SA_DQ<9>")
	)
	(segment
		(start 54.279292 -305.518312)
		(end 54.027324 -305.266344)
		(width 0.20066)
		(layer "F.Cu")
		(net "M_A_CPU1_SA_DQ<9>")
	)
	(segment
		(start 58.704226 -304.841656)
		(end 58.643012 -304.841656)
		(width 0.101854)
		(layer "F.Cu")
		(net "M_A_CPU1_SA_DQ<9>")
	)
	(segment
		(start 54.66334 -305.518312)
		(end 54.279292 -305.518312)
		(width 0.20066)
		(layer "F.Cu")
		(net "M_A_CPU1_SA_DQ<9>")
	)
	(segment
		(start 54.02707 -305.266598)
		(end 53.403246 -305.266598)
		(width 0.20066)
		(layer "F.Cu")
		(net "M_A_CPU1_SA_DQ<9>")
	)
	(segment
		(start 58.82132 -304.841656)
		(end 58.704226 -304.841656)
		(width 0.20066)
		(layer "F.Cu")
		(net "M_A_CPU1_SA_DQ<9>")
	)
	(segment
		(start 60.947046 -305.266598)
		(end 59.246262 -305.266598)
		(width 0.20066)
		(layer "F.Cu")
		(net "M_A_CPU1_SA_DQ<9>")
	)
	(segment
		(start 56.37911 -304.833528)
		(end 55.085996 -304.833528)
		(width 0.20066)
		(layer "F.Cu")
		(net "M_A_CPU1_SA_DQ<9>")
	)
	(segment
		(start 62.051946 -305.266598)
		(end 60.947046 -305.266598)
		(width 0.20066)
		(layer "F.Cu")
		(net "M_A_CPU1_SA_DQ<9>")
	)
	(segment
		(start 54.027324 -305.266344)
		(end 54.02707 -305.266598)
		(width 0.20066)
		(layer "F.Cu")
		(net "M_A_CPU1_SA_DQ<9>")
	)
	(segment
		(start 56.433212 -304.841656)
		(end 56.426354 -304.841656)
		(width 0.101854)
		(layer "F.Cu")
		(net "M_A_CPU1_SA_DQ<9>")
	)
	(segment
		(start 56.418226 -304.833528)
		(end 56.37911 -304.833528)
		(width 0.101854)
		(layer "F.Cu")
		(net "M_A_CPU1_SA_DQ<9>")
	)
	(segment
		(start 88.725248 -270.475456)
		(end 88.725248 -271.011142)
		(width 0.20066)
		(layer "F.Cu")
		(net "M_A_CPU1_SA_DQ<9>")
	)
	(segment
		(start 55.085996 -304.833528)
		(end 54.897528 -305.021996)
		(width 0.20066)
		(layer "F.Cu")
		(net "M_A_CPU1_SA_DQ<9>")
	)
	(segment
		(start 88.725248 -271.011142)
		(end 88.724994 -271.011396)
		(width 0.20066)
		(layer "F.Cu")
		(net "M_A_CPU1_SA_DQ<9>")
	)
	(segment
		(start 78.509114 -280.980642)
		(end 77.212444 -284.110938)
		(width 0.18288)
		(layer "In2.Cu")
		(net "M_A_CPU1_SA_DQ<9>")
	)
	(segment
		(start 75.55992 -285.763462)
		(end 72.358758 -293.49573)
		(width 0.18288)
		(layer "In2.Cu")
		(net "M_A_CPU1_SA_DQ<9>")
	)
	(segment
		(start 63.579248 -304.295556)
		(end 63.419228 -304.135536)
		(width 0.18288)
		(layer "In2.Cu")
		(net "M_A_CPU1_SA_DQ<9>")
	)
	(segment
		(start 63.721488 -304.688494)
		(end 63.579248 -304.546254)
		(width 0.18288)
		(layer "In2.Cu")
		(net "M_A_CPU1_SA_DQ<9>")
	)
	(segment
		(start 69.974968 -300.665388)
		(end 68.956936 -303.123092)
		(width 0.18288)
		(layer "In2.Cu")
		(net "M_A_CPU1_SA_DQ<9>")
	)
	(segment
		(start 63.419228 -304.135536)
		(end 62.841886 -304.135536)
		(width 0.18288)
		(layer "In2.Cu")
		(net "M_A_CPU1_SA_DQ<9>")
	)
	(segment
		(start 87.128096 -271.500854)
		(end 87.119206 -271.505934)
		(width 0.088646)
		(layer "In2.Cu")
		(net "M_A_CPU1_SA_DQ<9>")
	)
	(segment
		(start 85.760306 -271.694656)
		(end 85.585046 -271.869916)
		(width 0.088646)
		(layer "In2.Cu")
		(net "M_A_CPU1_SA_DQ<9>")
	)
	(segment
		(start 62.841886 -304.135536)
		(end 62.681866 -304.295556)
		(width 0.18288)
		(layer "In2.Cu")
		(net "M_A_CPU1_SA_DQ<9>")
	)
	(segment
		(start 71.328026 -294.526716)
		(end 69.974968 -297.795188)
		(width 0.18288)
		(layer "In2.Cu")
		(net "M_A_CPU1_SA_DQ<9>")
	)
	(segment
		(start 64.244982 -304.841656)
		(end 64.09182 -304.688494)
		(width 0.18288)
		(layer "In2.Cu")
		(net "M_A_CPU1_SA_DQ<9>")
	)
	(segment
		(start 66.396616 -304.841656)
		(end 64.244982 -304.841656)
		(width 0.18288)
		(layer "In2.Cu")
		(net "M_A_CPU1_SA_DQ<9>")
	)
	(segment
		(start 86.988396 -271.642332)
		(end 86.936072 -271.694656)
		(width 0.088646)
		(layer "In2.Cu")
		(net "M_A_CPU1_SA_DQ<9>")
	)
	(segment
		(start 82.058002 -277.22449)
		(end 78.655672 -280.62682)
		(width 0.18288)
		(layer "In2.Cu")
		(net "M_A_CPU1_SA_DQ<9>")
	)
	(segment
		(start 64.09182 -304.688494)
		(end 63.721488 -304.688494)
		(width 0.18288)
		(layer "In2.Cu")
		(net "M_A_CPU1_SA_DQ<9>")
	)
	(segment
		(start 62.681866 -304.636678)
		(end 62.051946 -305.266598)
		(width 0.18288)
		(layer "In2.Cu")
		(net "M_A_CPU1_SA_DQ<9>")
	)
	(segment
		(start 88.09609 -271.484598)
		(end 88.067896 -271.500854)
		(width 0.088646)
		(layer "In2.Cu")
		(net "M_A_CPU1_SA_DQ<9>")
	)
	(segment
		(start 68.956936 -303.123092)
		(end 67.133978 -304.94605)
		(width 0.18288)
		(layer "In2.Cu")
		(net "M_A_CPU1_SA_DQ<9>")
	)
	(segment
		(start 86.936072 -271.694656)
		(end 85.760306 -271.694656)
		(width 0.088646)
		(layer "In2.Cu")
		(net "M_A_CPU1_SA_DQ<9>")
	)
	(segment
		(start 88.724994 -271.011396)
		(end 88.09609 -271.484598)
		(width 0.088646)
		(layer "In2.Cu")
		(net "M_A_CPU1_SA_DQ<9>")
	)
	(segment
		(start 83.349592 -274.10537)
		(end 82.058002 -277.22449)
		(width 0.18288)
		(layer "In2.Cu")
		(net "M_A_CPU1_SA_DQ<9>")
	)
	(segment
		(start 67.133978 -304.94605)
		(end 66.50101 -304.94605)
		(width 0.18288)
		(layer "In2.Cu")
		(net "M_A_CPU1_SA_DQ<9>")
	)
	(segment
		(start 78.655672 -280.62682)
		(end 78.509114 -280.980642)
		(width 0.18288)
		(layer "In2.Cu")
		(net "M_A_CPU1_SA_DQ<9>")
	)
	(segment
		(start 69.974968 -297.795188)
		(end 69.974968 -300.665388)
		(width 0.18288)
		(layer "In2.Cu")
		(net "M_A_CPU1_SA_DQ<9>")
	)
	(segment
		(start 62.681866 -304.295556)
		(end 62.681866 -304.636678)
		(width 0.18288)
		(layer "In2.Cu")
		(net "M_A_CPU1_SA_DQ<9>")
	)
	(segment
		(start 72.358758 -293.49573)
		(end 71.328026 -294.526716)
		(width 0.18288)
		(layer "In2.Cu")
		(net "M_A_CPU1_SA_DQ<9>")
	)
	(segment
		(start 66.50101 -304.94605)
		(end 66.396616 -304.841656)
		(width 0.18288)
		(layer "In2.Cu")
		(net "M_A_CPU1_SA_DQ<9>")
	)
	(segment
		(start 77.212444 -284.110938)
		(end 75.55992 -285.763462)
		(width 0.18288)
		(layer "In2.Cu")
		(net "M_A_CPU1_SA_DQ<9>")
	)
	(segment
		(start 85.585046 -271.869916)
		(end 83.349592 -274.10537)
		(width 0.18288)
		(layer "In2.Cu")
		(net "M_A_CPU1_SA_DQ<9>")
	)
	(segment
		(start 63.579248 -304.546254)
		(end 63.579248 -304.295556)
		(width 0.18288)
		(layer "In2.Cu")
		(net "M_A_CPU1_SA_DQ<9>")
	)
	(arc
		(start 87.119206 -271.505934)
		(mid 87.045055 -271.565747)
		(end 86.988396 -271.642332)
		(width 0.088646)
		(layer "In2.Cu")
		(net "M_A_CPU1_SA_DQ<9>")
	)
	(arc
		(start 88.067896 -271.500854)
		(mid 87.785194 -271.576596)
		(end 87.502492 -271.500854)
		(width 0.088646)
		(layer "In2.Cu")
		(net "M_A_CPU1_SA_DQ<9>")
	)
	(arc
		(start 87.502492 -271.500854)
		(mid 87.315294 -271.450711)
		(end 87.128096 -271.500854)
		(width 0.088646)
		(layer "In2.Cu")
		(net "M_A_CPU1_SA_DQ<9>")
	)
	(segment
		(start 54.02707 -306.96662)
		(end 53.403246 -306.96662)
		(width 0.20066)
		(layer "F.Cu")
		(net "M_A_CPU1_SA_DQ<8>")
	)
	(segment
		(start 89.194894 -271.289272)
		(end 89.194894 -271.824958)
		(width 0.20066)
		(layer "F.Cu")
		(net "M_A_CPU1_SA_DQ<8>")
	)
	(segment
		(start 59.32932 -306.541678)
		(end 58.704226 -306.541678)
		(width 0.20066)
		(layer "F.Cu")
		(net "M_A_CPU1_SA_DQ<8>")
	)
	(segment
		(start 89.194894 -271.824958)
		(end 89.195148 -271.825212)
		(width 0.20066)
		(layer "F.Cu")
		(net "M_A_CPU1_SA_DQ<8>")
	)
	(segment
		(start 62.051946 -306.96662)
		(end 60.947046 -306.96662)
		(width 0.20066)
		(layer "F.Cu")
		(net "M_A_CPU1_SA_DQ<8>")
	)
	(segment
		(start 58.617612 -306.541678)
		(end 56.433212 -306.541678)
		(width 0.1016)
		(layer "F.Cu")
		(net "M_A_CPU1_SA_DQ<8>")
	)
	(segment
		(start 60.947046 -306.96662)
		(end 59.754262 -306.96662)
		(width 0.20066)
		(layer "F.Cu")
		(net "M_A_CPU1_SA_DQ<8>")
	)
	(segment
		(start 54.897528 -306.984146)
		(end 54.66334 -307.218334)
		(width 0.20066)
		(layer "F.Cu")
		(net "M_A_CPU1_SA_DQ<8>")
	)
	(segment
		(start 54.027324 -306.966366)
		(end 54.02707 -306.96662)
		(width 0.20066)
		(layer "F.Cu")
		(net "M_A_CPU1_SA_DQ<8>")
	)
	(segment
		(start 55.089298 -306.529994)
		(end 54.897528 -306.721764)
		(width 0.20066)
		(layer "F.Cu")
		(net "M_A_CPU1_SA_DQ<8>")
	)
	(segment
		(start 58.704226 -306.541678)
		(end 58.617612 -306.541678)
		(width 0.101854)
		(layer "F.Cu")
		(net "M_A_CPU1_SA_DQ<8>")
	)
	(segment
		(start 54.897528 -306.721764)
		(end 54.897528 -306.984146)
		(width 0.20066)
		(layer "F.Cu")
		(net "M_A_CPU1_SA_DQ<8>")
	)
	(segment
		(start 56.415686 -306.541678)
		(end 56.404002 -306.529994)
		(width 0.101854)
		(layer "F.Cu")
		(net "M_A_CPU1_SA_DQ<8>")
	)
	(segment
		(start 56.37911 -306.529994)
		(end 55.089298 -306.529994)
		(width 0.20066)
		(layer "F.Cu")
		(net "M_A_CPU1_SA_DQ<8>")
	)
	(segment
		(start 56.404002 -306.529994)
		(end 56.37911 -306.529994)
		(width 0.101854)
		(layer "F.Cu")
		(net "M_A_CPU1_SA_DQ<8>")
	)
	(segment
		(start 54.279292 -307.218334)
		(end 54.027324 -306.966366)
		(width 0.20066)
		(layer "F.Cu")
		(net "M_A_CPU1_SA_DQ<8>")
	)
	(segment
		(start 56.433212 -306.541678)
		(end 56.415686 -306.541678)
		(width 0.101854)
		(layer "F.Cu")
		(net "M_A_CPU1_SA_DQ<8>")
	)
	(segment
		(start 59.754262 -306.96662)
		(end 59.32932 -306.541678)
		(width 0.20066)
		(layer "F.Cu")
		(net "M_A_CPU1_SA_DQ<8>")
	)
	(segment
		(start 54.66334 -307.218334)
		(end 54.279292 -307.218334)
		(width 0.20066)
		(layer "F.Cu")
		(net "M_A_CPU1_SA_DQ<8>")
	)
	(segment
		(start 70.482968 -300.795436)
		(end 69.407786 -303.391062)
		(width 0.18288)
		(layer "In2.Cu")
		(net "M_A_CPU1_SA_DQ<8>")
	)
	(segment
		(start 85.218016 -272.72615)
		(end 84.080858 -273.863308)
		(width 0.088646)
		(layer "In2.Cu")
		(net "M_A_CPU1_SA_DQ<8>")
	)
	(segment
		(start 71.731632 -294.882062)
		(end 70.482968 -297.896534)
		(width 0.18288)
		(layer "In2.Cu")
		(net "M_A_CPU1_SA_DQ<8>")
	)
	(segment
		(start 75.993752 -286.04845)
		(end 72.761094 -293.852346)
		(width 0.18288)
		(layer "In2.Cu")
		(net "M_A_CPU1_SA_DQ<8>")
	)
	(segment
		(start 67.271138 -305.52771)
		(end 66.71691 -305.52771)
		(width 0.18288)
		(layer "In2.Cu")
		(net "M_A_CPU1_SA_DQ<8>")
	)
	(segment
		(start 87.128096 -272.14957)
		(end 87.113364 -272.140934)
		(width 0.088646)
		(layer "In2.Cu")
		(net "M_A_CPU1_SA_DQ<8>")
	)
	(segment
		(start 69.407786 -303.391062)
		(end 67.271138 -305.52771)
		(width 0.18288)
		(layer "In2.Cu")
		(net "M_A_CPU1_SA_DQ<8>")
	)
	(segment
		(start 66.55308 -305.69154)
		(end 64.36233 -305.69154)
		(width 0.18288)
		(layer "In2.Cu")
		(net "M_A_CPU1_SA_DQ<8>")
	)
	(segment
		(start 89.00795 -272.14957)
		(end 88.997536 -272.143474)
		(width 0.088646)
		(layer "In2.Cu")
		(net "M_A_CPU1_SA_DQ<8>")
	)
	(segment
		(start 87.128858 -272.14957)
		(end 87.128096 -272.14957)
		(width 0.088646)
		(layer "In2.Cu")
		(net "M_A_CPU1_SA_DQ<8>")
	)
	(segment
		(start 66.71691 -305.52771)
		(end 66.55308 -305.69154)
		(width 0.18288)
		(layer "In2.Cu")
		(net "M_A_CPU1_SA_DQ<8>")
	)
	(segment
		(start 88.076532 -272.154396)
		(end 88.06815 -272.14957)
		(width 0.088646)
		(layer "In2.Cu")
		(net "M_A_CPU1_SA_DQ<8>")
	)
	(segment
		(start 89.507822 -271.825212)
		(end 89.564972 -271.882362)
		(width 0.088646)
		(layer "In2.Cu")
		(net "M_A_CPU1_SA_DQ<8>")
	)
	(segment
		(start 72.761094 -293.852346)
		(end 71.731632 -294.882062)
		(width 0.18288)
		(layer "In2.Cu")
		(net "M_A_CPU1_SA_DQ<8>")
	)
	(segment
		(start 86.67369 -272.104358)
		(end 85.291168 -272.677128)
		(width 0.088646)
		(layer "In2.Cu")
		(net "M_A_CPU1_SA_DQ<8>")
	)
	(segment
		(start 79.211424 -280.613358)
		(end 79.059278 -280.980642)
		(width 0.18288)
		(layer "In2.Cu")
		(net "M_A_CPU1_SA_DQ<8>")
	)
	(segment
		(start 63.915544 -305.79568)
		(end 63.621412 -305.9176)
		(width 0.18288)
		(layer "In2.Cu")
		(net "M_A_CPU1_SA_DQ<8>")
	)
	(segment
		(start 83.643724 -274.300442)
		(end 82.313018 -277.511764)
		(width 0.18288)
		(layer "In2.Cu")
		(net "M_A_CPU1_SA_DQ<8>")
	)
	(segment
		(start 82.313018 -277.511764)
		(end 79.211424 -280.613358)
		(width 0.18288)
		(layer "In2.Cu")
		(net "M_A_CPU1_SA_DQ<8>")
	)
	(segment
		(start 63.621412 -305.9176)
		(end 62.051946 -306.96662)
		(width 0.18288)
		(layer "In2.Cu")
		(net "M_A_CPU1_SA_DQ<8>")
	)
	(segment
		(start 89.195148 -271.825212)
		(end 89.507822 -271.825212)
		(width 0.088646)
		(layer "In2.Cu")
		(net "M_A_CPU1_SA_DQ<8>")
	)
	(segment
		(start 70.482968 -297.896534)
		(end 70.482968 -300.795436)
		(width 0.18288)
		(layer "In2.Cu")
		(net "M_A_CPU1_SA_DQ<8>")
	)
	(segment
		(start 77.643228 -284.398974)
		(end 75.993752 -286.04845)
		(width 0.18288)
		(layer "In2.Cu")
		(net "M_A_CPU1_SA_DQ<8>")
	)
	(segment
		(start 64.36233 -305.69154)
		(end 63.915544 -305.79568)
		(width 0.18288)
		(layer "In2.Cu")
		(net "M_A_CPU1_SA_DQ<8>")
	)
	(segment
		(start 84.080858 -273.863308)
		(end 83.643724 -274.300442)
		(width 0.18288)
		(layer "In2.Cu")
		(net "M_A_CPU1_SA_DQ<8>")
	)
	(segment
		(start 79.059278 -280.980642)
		(end 77.643228 -284.398974)
		(width 0.18288)
		(layer "In2.Cu")
		(net "M_A_CPU1_SA_DQ<8>")
	)
	(arc
		(start 88.442292 -272.14957)
		(mid 88.260041 -272.199681)
		(end 88.076532 -272.154396)
		(width 0.088646)
		(layer "In2.Cu")
		(net "M_A_CPU1_SA_DQ<8>")
	)
	(arc
		(start 88.06815 -272.14957)
		(mid 87.785702 -272.073955)
		(end 87.503254 -272.14957)
		(width 0.088646)
		(layer "In2.Cu")
		(net "M_A_CPU1_SA_DQ<8>")
	)
	(arc
		(start 85.291168 -272.677128)
		(mid 85.252193 -272.698056)
		(end 85.218016 -272.72615)
		(width 0.088646)
		(layer "In2.Cu")
		(net "M_A_CPU1_SA_DQ<8>")
	)
	(arc
		(start 89.382346 -272.14957)
		(mid 89.195148 -272.199713)
		(end 89.00795 -272.14957)
		(width 0.088646)
		(layer "In2.Cu")
		(net "M_A_CPU1_SA_DQ<8>")
	)
	(arc
		(start 87.503254 -272.14957)
		(mid 87.316056 -272.199713)
		(end 87.128858 -272.14957)
		(width 0.088646)
		(layer "In2.Cu")
		(net "M_A_CPU1_SA_DQ<8>")
	)
	(arc
		(start 87.113364 -272.140934)
		(mid 86.941152 -272.081669)
		(end 86.759034 -272.080228)
		(width 0.088646)
		(layer "In2.Cu")
		(net "M_A_CPU1_SA_DQ<8>")
	)
	(arc
		(start 89.564972 -271.882362)
		(mid 89.504029 -272.036725)
		(end 89.382346 -272.14957)
		(width 0.088646)
		(layer "In2.Cu")
		(net "M_A_CPU1_SA_DQ<8>")
	)
	(arc
		(start 88.997536 -272.143474)
		(mid 88.719104 -272.07366)
		(end 88.442292 -272.14957)
		(width 0.088646)
		(layer "In2.Cu")
		(net "M_A_CPU1_SA_DQ<8>")
	)
	(arc
		(start 86.759034 -272.080228)
		(mid 86.715646 -272.089756)
		(end 86.67369 -272.104358)
		(width 0.088646)
		(layer "In2.Cu")
		(net "M_A_CPU1_SA_DQ<8>")
	)
	(segment
		(start 69.001894 -303.442624)
		(end 68.630292 -303.071022)
		(width 0.20066)
		(layer "F.Cu")
		(net "M_A_CPU1_SA_DQ<7>")
	)
	(segment
		(start 68.498974 -304.229516)
		(end 67.202304 -305.526186)
		(width 0.20066)
		(layer "F.Cu")
		(net "M_A_CPU1_SA_DQ<7>")
	)
	(segment
		(start 83.198716 -277.660862)
		(end 82.928714 -277.930864)
		(width 0.088646)
		(layer "F.Cu")
		(net "M_A_CPU1_SA_DQ<7>")
	)
	(segment
		(start 82.928714 -277.930864)
		(end 82.170778 -278.6888)
		(width 0.1016)
		(layer "F.Cu")
		(net "M_A_CPU1_SA_DQ<7>")
	)
	(segment
		(start 71.36384 -300.053502)
		(end 71.144892 -300.27245)
		(width 0.20066)
		(layer "F.Cu")
		(net "M_A_CPU1_SA_DQ<7>")
	)
	(segment
		(start 70.641972 -301.059342)
		(end 70.358 -301.059342)
		(width 0.20066)
		(layer "F.Cu")
		(net "M_A_CPU1_SA_DQ<7>")
	)
	(segment
		(start 59.188858 -307.816504)
		(end 59.314842 -307.942488)
		(width 0.20066)
		(layer "F.Cu")
		(net "M_A_CPU1_SA_DQ<7>")
	)
	(segment
		(start 70.358 -301.059342)
		(end 70.139052 -301.27829)
		(width 0.20066)
		(layer "F.Cu")
		(net "M_A_CPU1_SA_DQ<7>")
	)
	(segment
		(start 69.133212 -302.568102)
		(end 69.504814 -302.939704)
		(width 0.20066)
		(layer "F.Cu")
		(net "M_A_CPU1_SA_DQ<7>")
	)
	(segment
		(start 62.072012 -308.2417)
		(end 62.147958 -308.2417)
		(width 0.101854)
		(layer "F.Cu")
		(net "M_A_CPU1_SA_DQ<7>")
	)
	(segment
		(start 71.144892 -300.27245)
		(end 71.144892 -300.556422)
		(width 0.20066)
		(layer "F.Cu")
		(net "M_A_CPU1_SA_DQ<7>")
	)
	(segment
		(start 59.461146 -308.248812)
		(end 59.822842 -308.248812)
		(width 0.20066)
		(layer "F.Cu")
		(net "M_A_CPU1_SA_DQ<7>")
	)
	(segment
		(start 87.315294 -276.172676)
		(end 86.863174 -275.980652)
		(width 0.088646)
		(layer "F.Cu")
		(net "M_A_CPU1_SA_DQ<7>")
	)
	(segment
		(start 67.202304 -305.526186)
		(end 67.202304 -306.988718)
		(width 0.20066)
		(layer "F.Cu")
		(net "M_A_CPU1_SA_DQ<7>")
	)
	(segment
		(start 59.822842 -308.248812)
		(end 59.837066 -308.248812)
		(width 0.101854)
		(layer "F.Cu")
		(net "M_A_CPU1_SA_DQ<7>")
	)
	(segment
		(start 69.504814 -302.939704)
		(end 69.504814 -303.223676)
		(width 0.20066)
		(layer "F.Cu")
		(net "M_A_CPU1_SA_DQ<7>")
	)
	(segment
		(start 81.490312 -281.947112)
		(end 81.490312 -294.142922)
		(width 0.1016)
		(layer "F.Cu")
		(net "M_A_CPU1_SA_DQ<7>")
	)
	(segment
		(start 75.913488 -299.719746)
		(end 73.008744 -299.719746)
		(width 0.20066)
		(layer "F.Cu")
		(net "M_A_CPU1_SA_DQ<7>")
	)
	(segment
		(start 82.170778 -278.6888)
		(end 82.123788 -278.776938)
		(width 0.1016)
		(layer "F.Cu")
		(net "M_A_CPU1_SA_DQ<7>")
	)
	(segment
		(start 59.887612 -308.2417)
		(end 62.072012 -308.2417)
		(width 0.1016)
		(layer "F.Cu")
		(net "M_A_CPU1_SA_DQ<7>")
	)
	(segment
		(start 72.019414 -300.425104)
		(end 71.647812 -300.053502)
		(width 0.20066)
		(layer "F.Cu")
		(net "M_A_CPU1_SA_DQ<7>")
	)
	(segment
		(start 71.144892 -300.556422)
		(end 71.516494 -300.928024)
		(width 0.20066)
		(layer "F.Cu")
		(net "M_A_CPU1_SA_DQ<7>")
	)
	(segment
		(start 68.498974 -303.945544)
		(end 68.498974 -304.229516)
		(width 0.20066)
		(layer "F.Cu")
		(net "M_A_CPU1_SA_DQ<7>")
	)
	(segment
		(start 85.435694 -275.79828)
		(end 84.938108 -275.79828)
		(width 0.088646)
		(layer "F.Cu")
		(net "M_A_CPU1_SA_DQ<7>")
	)
	(segment
		(start 83.198716 -277.40737)
		(end 83.198716 -277.660862)
		(width 0.088646)
		(layer "F.Cu")
		(net "M_A_CPU1_SA_DQ<7>")
	)
	(segment
		(start 68.34632 -303.071022)
		(end 68.127372 -303.28997)
		(width 0.20066)
		(layer "F.Cu")
		(net "M_A_CPU1_SA_DQ<7>")
	)
	(segment
		(start 83.600798 -277.005288)
		(end 83.198716 -277.40737)
		(width 0.088646)
		(layer "F.Cu")
		(net "M_A_CPU1_SA_DQ<7>")
	)
	(segment
		(start 71.013574 -301.430944)
		(end 70.641972 -301.059342)
		(width 0.20066)
		(layer "F.Cu")
		(net "M_A_CPU1_SA_DQ<7>")
	)
	(segment
		(start 71.516494 -301.211996)
		(end 71.297546 -301.430944)
		(width 0.20066)
		(layer "F.Cu")
		(net "M_A_CPU1_SA_DQ<7>")
	)
	(segment
		(start 70.510654 -302.217836)
		(end 70.291706 -302.436784)
		(width 0.20066)
		(layer "F.Cu")
		(net "M_A_CPU1_SA_DQ<7>")
	)
	(segment
		(start 59.188604 -307.816758)
		(end 59.188858 -307.816504)
		(width 0.20066)
		(layer "F.Cu")
		(net "M_A_CPU1_SA_DQ<7>")
	)
	(segment
		(start 82.123788 -278.776938)
		(end 81.490312 -281.947112)
		(width 0.1016)
		(layer "F.Cu")
		(net "M_A_CPU1_SA_DQ<7>")
	)
	(segment
		(start 70.139052 -301.562262)
		(end 70.510654 -301.933864)
		(width 0.20066)
		(layer "F.Cu")
		(net "M_A_CPU1_SA_DQ<7>")
	)
	(segment
		(start 64.219074 -307.816758)
		(end 65.047114 -307.816758)
		(width 0.20066)
		(layer "F.Cu")
		(net "M_A_CPU1_SA_DQ<7>")
	)
	(segment
		(start 68.127372 -303.573942)
		(end 68.498974 -303.945544)
		(width 0.20066)
		(layer "F.Cu")
		(net "M_A_CPU1_SA_DQ<7>")
	)
	(segment
		(start 63.171578 -307.816504)
		(end 63.50254 -308.147466)
		(width 0.20066)
		(layer "F.Cu")
		(net "M_A_CPU1_SA_DQ<7>")
	)
	(segment
		(start 59.314842 -308.102508)
		(end 59.461146 -308.248812)
		(width 0.20066)
		(layer "F.Cu")
		(net "M_A_CPU1_SA_DQ<7>")
	)
	(segment
		(start 67.202304 -306.988718)
		(end 66.374264 -307.816758)
		(width 0.20066)
		(layer "F.Cu")
		(net "M_A_CPU1_SA_DQ<7>")
	)
	(segment
		(start 83.7311 -277.005288)
		(end 83.600798 -277.005288)
		(width 0.088646)
		(layer "F.Cu")
		(net "M_A_CPU1_SA_DQ<7>")
	)
	(segment
		(start 80.765142 -294.868092)
		(end 75.913488 -299.719746)
		(width 0.20066)
		(layer "F.Cu")
		(net "M_A_CPU1_SA_DQ<7>")
	)
	(segment
		(start 68.127372 -303.28997)
		(end 68.127372 -303.573942)
		(width 0.20066)
		(layer "F.Cu")
		(net "M_A_CPU1_SA_DQ<7>")
	)
	(segment
		(start 70.139052 -301.27829)
		(end 70.139052 -301.562262)
		(width 0.20066)
		(layer "F.Cu")
		(net "M_A_CPU1_SA_DQ<7>")
	)
	(segment
		(start 71.516494 -300.928024)
		(end 71.516494 -301.211996)
		(width 0.20066)
		(layer "F.Cu")
		(net "M_A_CPU1_SA_DQ<7>")
	)
	(segment
		(start 73.008744 -299.719746)
		(end 72.303386 -300.425104)
		(width 0.20066)
		(layer "F.Cu")
		(net "M_A_CPU1_SA_DQ<7>")
	)
	(segment
		(start 69.504814 -303.223676)
		(end 69.285866 -303.442624)
		(width 0.20066)
		(layer "F.Cu")
		(net "M_A_CPU1_SA_DQ<7>")
	)
	(segment
		(start 63.50254 -308.147466)
		(end 63.888366 -308.147466)
		(width 0.20066)
		(layer "F.Cu")
		(net "M_A_CPU1_SA_DQ<7>")
	)
	(segment
		(start 69.133212 -302.28413)
		(end 69.133212 -302.568102)
		(width 0.20066)
		(layer "F.Cu")
		(net "M_A_CPU1_SA_DQ<7>")
	)
	(segment
		(start 62.147958 -308.2417)
		(end 62.417198 -308.2417)
		(width 0.20066)
		(layer "F.Cu")
		(net "M_A_CPU1_SA_DQ<7>")
	)
	(segment
		(start 62.417198 -308.2417)
		(end 62.842394 -307.816504)
		(width 0.20066)
		(layer "F.Cu")
		(net "M_A_CPU1_SA_DQ<7>")
	)
	(segment
		(start 71.647812 -300.053502)
		(end 71.36384 -300.053502)
		(width 0.20066)
		(layer "F.Cu")
		(net "M_A_CPU1_SA_DQ<7>")
	)
	(segment
		(start 70.291706 -302.436784)
		(end 70.007734 -302.436784)
		(width 0.20066)
		(layer "F.Cu")
		(net "M_A_CPU1_SA_DQ<7>")
	)
	(segment
		(start 59.837066 -308.248812)
		(end 59.844178 -308.2417)
		(width 0.101854)
		(layer "F.Cu")
		(net "M_A_CPU1_SA_DQ<7>")
	)
	(segment
		(start 68.630292 -303.071022)
		(end 68.34632 -303.071022)
		(width 0.20066)
		(layer "F.Cu")
		(net "M_A_CPU1_SA_DQ<7>")
	)
	(segment
		(start 69.35216 -302.065182)
		(end 69.133212 -302.28413)
		(width 0.20066)
		(layer "F.Cu")
		(net "M_A_CPU1_SA_DQ<7>")
	)
	(segment
		(start 84.938108 -275.79828)
		(end 83.7311 -277.005288)
		(width 0.088646)
		(layer "F.Cu")
		(net "M_A_CPU1_SA_DQ<7>")
	)
	(segment
		(start 86.783672 -275.940774)
		(end 86.49335 -275.772372)
		(width 0.088646)
		(layer "F.Cu")
		(net "M_A_CPU1_SA_DQ<7>")
	)
	(segment
		(start 59.314842 -307.942488)
		(end 59.314842 -308.102508)
		(width 0.20066)
		(layer "F.Cu")
		(net "M_A_CPU1_SA_DQ<7>")
	)
	(segment
		(start 69.636132 -302.065182)
		(end 69.35216 -302.065182)
		(width 0.20066)
		(layer "F.Cu")
		(net "M_A_CPU1_SA_DQ<7>")
	)
	(segment
		(start 71.297546 -301.430944)
		(end 71.013574 -301.430944)
		(width 0.20066)
		(layer "F.Cu")
		(net "M_A_CPU1_SA_DQ<7>")
	)
	(segment
		(start 59.844178 -308.2417)
		(end 59.887612 -308.2417)
		(width 0.101854)
		(layer "F.Cu")
		(net "M_A_CPU1_SA_DQ<7>")
	)
	(segment
		(start 62.842394 -307.816504)
		(end 63.171578 -307.816504)
		(width 0.20066)
		(layer "F.Cu")
		(net "M_A_CPU1_SA_DQ<7>")
	)
	(segment
		(start 66.374264 -307.816758)
		(end 65.047114 -307.816758)
		(width 0.20066)
		(layer "F.Cu")
		(net "M_A_CPU1_SA_DQ<7>")
	)
	(segment
		(start 81.490312 -294.142922)
		(end 80.765142 -294.868092)
		(width 0.1016)
		(layer "F.Cu")
		(net "M_A_CPU1_SA_DQ<7>")
	)
	(segment
		(start 70.510654 -301.933864)
		(end 70.510654 -302.217836)
		(width 0.20066)
		(layer "F.Cu")
		(net "M_A_CPU1_SA_DQ<7>")
	)
	(segment
		(start 86.144354 -275.771864)
		(end 86.011766 -275.848318)
		(width 0.088646)
		(layer "F.Cu")
		(net "M_A_CPU1_SA_DQ<7>")
	)
	(segment
		(start 57.503314 -307.816758)
		(end 59.188604 -307.816758)
		(width 0.20066)
		(layer "F.Cu")
		(net "M_A_CPU1_SA_DQ<7>")
	)
	(segment
		(start 69.285866 -303.442624)
		(end 69.001894 -303.442624)
		(width 0.20066)
		(layer "F.Cu")
		(net "M_A_CPU1_SA_DQ<7>")
	)
	(segment
		(start 70.007734 -302.436784)
		(end 69.636132 -302.065182)
		(width 0.20066)
		(layer "F.Cu")
		(net "M_A_CPU1_SA_DQ<7>")
	)
	(segment
		(start 72.303386 -300.425104)
		(end 72.019414 -300.425104)
		(width 0.20066)
		(layer "F.Cu")
		(net "M_A_CPU1_SA_DQ<7>")
	)
	(segment
		(start 63.888366 -308.147466)
		(end 64.219074 -307.816758)
		(width 0.20066)
		(layer "F.Cu")
		(net "M_A_CPU1_SA_DQ<7>")
	)
	(arc
		(start 85.622892 -275.848318)
		(mid 85.532585 -275.810989)
		(end 85.435694 -275.79828)
		(width 0.088646)
		(layer "F.Cu")
		(net "M_A_CPU1_SA_DQ<7>")
	)
	(arc
		(start 86.49335 -275.772372)
		(mid 86.318911 -275.725227)
		(end 86.144354 -275.771864)
		(width 0.088646)
		(layer "F.Cu")
		(net "M_A_CPU1_SA_DQ<7>")
	)
	(arc
		(start 86.011766 -275.848318)
		(mid 85.817346 -275.90035)
		(end 85.622892 -275.848318)
		(width 0.088646)
		(layer "F.Cu")
		(net "M_A_CPU1_SA_DQ<7>")
	)
	(arc
		(start 86.863174 -275.980652)
		(mid 86.822807 -275.96194)
		(end 86.783672 -275.940774)
		(width 0.088646)
		(layer "F.Cu")
		(net "M_A_CPU1_SA_DQ<7>")
	)
	(segment
		(start 71.672958 -304.806604)
		(end 71.45401 -305.025552)
		(width 0.20066)
		(layer "F.Cu")
		(net "M_A_CPU1_SA_DQ<6>")
	)
	(segment
		(start 62.51702 -309.472076)
		(end 62.689994 -309.64505)
		(width 0.20066)
		(layer "F.Cu")
		(net "M_A_CPU1_SA_DQ<6>")
	)
	(segment
		(start 70.99173 -303.841404)
		(end 71.672958 -304.522632)
		(width 0.20066)
		(layer "F.Cu")
		(net "M_A_CPU1_SA_DQ<6>")
	)
	(segment
		(start 69.98589 -304.563272)
		(end 69.98589 -304.847244)
		(width 0.20066)
		(layer "F.Cu")
		(net "M_A_CPU1_SA_DQ<6>")
	)
	(segment
		(start 70.667118 -305.528472)
		(end 70.667118 -305.812444)
		(width 0.20066)
		(layer "F.Cu")
		(net "M_A_CPU1_SA_DQ<6>")
	)
	(segment
		(start 72.175878 -304.019712)
		(end 71.49465 -303.338484)
		(width 0.20066)
		(layer "F.Cu")
		(net "M_A_CPU1_SA_DQ<6>")
	)
	(segment
		(start 59.825128 -309.0799)
		(end 59.836812 -309.091584)
		(width 0.101854)
		(layer "F.Cu")
		(net "M_A_CPU1_SA_DQ<6>")
	)
	(segment
		(start 72.850248 -303.629314)
		(end 72.45985 -304.019712)
		(width 0.20066)
		(layer "F.Cu")
		(net "M_A_CPU1_SA_DQ<6>")
	)
	(segment
		(start 62.072012 -309.091584)
		(end 62.147958 -309.091584)
		(width 0.101854)
		(layer "F.Cu")
		(net "M_A_CPU1_SA_DQ<6>")
	)
	(segment
		(start 59.836812 -309.091584)
		(end 62.072012 -309.091584)
		(width 0.1016)
		(layer "F.Cu")
		(net "M_A_CPU1_SA_DQ<6>")
	)
	(segment
		(start 71.210678 -303.338484)
		(end 70.99173 -303.557432)
		(width 0.20066)
		(layer "F.Cu")
		(net "M_A_CPU1_SA_DQ<6>")
	)
	(segment
		(start 57.503314 -309.51678)
		(end 59.00039 -309.51678)
		(width 0.20066)
		(layer "F.Cu")
		(net "M_A_CPU1_SA_DQ<6>")
	)
	(segment
		(start 59.822842 -309.0799)
		(end 59.825128 -309.0799)
		(width 0.101854)
		(layer "F.Cu")
		(net "M_A_CPU1_SA_DQ<6>")
	)
	(segment
		(start 59.102752 -309.2069)
		(end 59.229752 -309.0799)
		(width 0.20066)
		(layer "F.Cu")
		(net "M_A_CPU1_SA_DQ<6>")
	)
	(segment
		(start 59.102752 -309.414418)
		(end 59.102752 -309.2069)
		(width 0.20066)
		(layer "F.Cu")
		(net "M_A_CPU1_SA_DQ<6>")
	)
	(segment
		(start 84.301584 -277.499572)
		(end 84.301584 -277.634446)
		(width 0.088646)
		(layer "F.Cu")
		(net "M_A_CPU1_SA_DQ<6>")
	)
	(segment
		(start 83.689698 -278.048212)
		(end 83.36788 -278.37003)
		(width 0.088646)
		(layer "F.Cu")
		(net "M_A_CPU1_SA_DQ<6>")
	)
	(segment
		(start 83.887818 -278.048212)
		(end 83.689698 -278.048212)
		(width 0.088646)
		(layer "F.Cu")
		(net "M_A_CPU1_SA_DQ<6>")
	)
	(segment
		(start 71.49465 -303.338484)
		(end 71.210678 -303.338484)
		(width 0.20066)
		(layer "F.Cu")
		(net "M_A_CPU1_SA_DQ<6>")
	)
	(segment
		(start 82.694018 -279.043892)
		(end 82.099912 -282.009596)
		(width 0.1016)
		(layer "F.Cu")
		(net "M_A_CPU1_SA_DQ<6>")
	)
	(segment
		(start 72.850248 -302.620426)
		(end 72.850248 -303.629314)
		(width 0.20066)
		(layer "F.Cu")
		(net "M_A_CPU1_SA_DQ<6>")
	)
	(segment
		(start 71.170038 -305.025552)
		(end 70.48881 -304.344324)
		(width 0.20066)
		(layer "F.Cu")
		(net "M_A_CPU1_SA_DQ<6>")
	)
	(segment
		(start 85.435694 -276.737826)
		(end 85.06333 -276.737826)
		(width 0.088646)
		(layer "F.Cu")
		(net "M_A_CPU1_SA_DQ<6>")
	)
	(segment
		(start 71.672958 -304.522632)
		(end 71.672958 -304.806604)
		(width 0.20066)
		(layer "F.Cu")
		(net "M_A_CPU1_SA_DQ<6>")
	)
	(segment
		(start 59.00039 -309.51678)
		(end 59.102752 -309.414418)
		(width 0.20066)
		(layer "F.Cu")
		(net "M_A_CPU1_SA_DQ<6>")
	)
	(segment
		(start 72.45985 -304.019712)
		(end 72.175878 -304.019712)
		(width 0.20066)
		(layer "F.Cu")
		(net "M_A_CPU1_SA_DQ<6>")
	)
	(segment
		(start 62.951614 -309.64505)
		(end 63.080138 -309.516526)
		(width 0.20066)
		(layer "F.Cu")
		(net "M_A_CPU1_SA_DQ<6>")
	)
	(segment
		(start 66.962782 -309.51678)
		(end 65.047114 -309.51678)
		(width 0.20066)
		(layer "F.Cu")
		(net "M_A_CPU1_SA_DQ<6>")
	)
	(segment
		(start 62.51702 -309.232554)
		(end 62.51702 -309.472076)
		(width 0.20066)
		(layer "F.Cu")
		(net "M_A_CPU1_SA_DQ<6>")
	)
	(segment
		(start 62.37605 -309.091584)
		(end 62.51702 -309.232554)
		(width 0.20066)
		(layer "F.Cu")
		(net "M_A_CPU1_SA_DQ<6>")
	)
	(segment
		(start 63.080138 -309.516526)
		(end 63.080392 -309.51678)
		(width 0.20066)
		(layer "F.Cu")
		(net "M_A_CPU1_SA_DQ<6>")
	)
	(segment
		(start 63.080392 -309.51678)
		(end 65.047114 -309.51678)
		(width 0.20066)
		(layer "F.Cu")
		(net "M_A_CPU1_SA_DQ<6>")
	)
	(segment
		(start 59.229752 -309.0799)
		(end 59.822842 -309.0799)
		(width 0.20066)
		(layer "F.Cu")
		(net "M_A_CPU1_SA_DQ<6>")
	)
	(segment
		(start 81.23809 -296.20464)
		(end 76.210414 -301.232316)
		(width 0.20066)
		(layer "F.Cu")
		(net "M_A_CPU1_SA_DQ<6>")
	)
	(segment
		(start 83.36788 -278.37003)
		(end 82.694018 -279.043892)
		(width 0.1016)
		(layer "F.Cu")
		(net "M_A_CPU1_SA_DQ<6>")
	)
	(segment
		(start 62.689994 -309.64505)
		(end 62.951614 -309.64505)
		(width 0.20066)
		(layer "F.Cu")
		(net "M_A_CPU1_SA_DQ<6>")
	)
	(segment
		(start 62.147958 -309.091584)
		(end 62.37605 -309.091584)
		(width 0.20066)
		(layer "F.Cu")
		(net "M_A_CPU1_SA_DQ<6>")
	)
	(segment
		(start 87.785194 -276.986492)
		(end 87.685118 -276.886162)
		(width 0.088646)
		(layer "F.Cu")
		(net "M_A_CPU1_SA_DQ<6>")
	)
	(segment
		(start 85.06333 -276.737826)
		(end 84.301584 -277.499572)
		(width 0.088646)
		(layer "F.Cu")
		(net "M_A_CPU1_SA_DQ<6>")
	)
	(segment
		(start 82.099912 -282.009596)
		(end 82.099912 -295.342818)
		(width 0.1016)
		(layer "F.Cu")
		(net "M_A_CPU1_SA_DQ<6>")
	)
	(segment
		(start 84.301584 -277.634446)
		(end 83.887818 -278.048212)
		(width 0.088646)
		(layer "F.Cu")
		(net "M_A_CPU1_SA_DQ<6>")
	)
	(segment
		(start 74.238358 -301.232316)
		(end 72.850248 -302.620426)
		(width 0.20066)
		(layer "F.Cu")
		(net "M_A_CPU1_SA_DQ<6>")
	)
	(segment
		(start 69.98589 -304.847244)
		(end 70.667118 -305.528472)
		(width 0.20066)
		(layer "F.Cu")
		(net "M_A_CPU1_SA_DQ<6>")
	)
	(segment
		(start 70.99173 -303.557432)
		(end 70.99173 -303.841404)
		(width 0.20066)
		(layer "F.Cu")
		(net "M_A_CPU1_SA_DQ<6>")
	)
	(segment
		(start 70.204838 -304.344324)
		(end 69.98589 -304.563272)
		(width 0.20066)
		(layer "F.Cu")
		(net "M_A_CPU1_SA_DQ<6>")
	)
	(segment
		(start 70.667118 -305.812444)
		(end 66.962782 -309.51678)
		(width 0.20066)
		(layer "F.Cu")
		(net "M_A_CPU1_SA_DQ<6>")
	)
	(segment
		(start 76.210414 -301.232316)
		(end 74.238358 -301.232316)
		(width 0.20066)
		(layer "F.Cu")
		(net "M_A_CPU1_SA_DQ<6>")
	)
	(segment
		(start 71.45401 -305.025552)
		(end 71.170038 -305.025552)
		(width 0.20066)
		(layer "F.Cu")
		(net "M_A_CPU1_SA_DQ<6>")
	)
	(segment
		(start 70.48881 -304.344324)
		(end 70.204838 -304.344324)
		(width 0.20066)
		(layer "F.Cu")
		(net "M_A_CPU1_SA_DQ<6>")
	)
	(segment
		(start 82.099912 -295.342818)
		(end 81.23809 -296.20464)
		(width 0.1016)
		(layer "F.Cu")
		(net "M_A_CPU1_SA_DQ<6>")
	)
	(segment
		(start 86.953852 -276.582886)
		(end 86.138004 -276.582886)
		(width 0.088646)
		(layer "F.Cu")
		(net "M_A_CPU1_SA_DQ<6>")
	)
	(arc
		(start 87.685118 -276.886162)
		(mid 87.349682 -276.661714)
		(end 86.953852 -276.582886)
		(width 0.088646)
		(layer "F.Cu")
		(net "M_A_CPU1_SA_DQ<6>")
	)
	(arc
		(start 86.138004 -276.582886)
		(mid 85.955933 -276.597191)
		(end 85.77834 -276.639782)
		(width 0.088646)
		(layer "F.Cu")
		(net "M_A_CPU1_SA_DQ<6>")
	)
	(arc
		(start 85.696552 -276.674326)
		(mid 85.56995 -276.721808)
		(end 85.435694 -276.737826)
		(width 0.088646)
		(layer "F.Cu")
		(net "M_A_CPU1_SA_DQ<6>")
	)
	(arc
		(start 85.77834 -276.639782)
		(mid 85.736735 -276.655371)
		(end 85.696552 -276.674326)
		(width 0.088646)
		(layer "F.Cu")
		(net "M_A_CPU1_SA_DQ<6>")
	)
	(segment
		(start 68.814696 -305.108356)
		(end 69.267832 -305.561492)
		(width 0.20066)
		(layer "F.Cu")
		(net "M_A_CPU1_SA_DQ<5>")
	)
	(segment
		(start 82.414364 -278.88692)
		(end 81.795112 -281.9781)
		(width 0.1016)
		(layer "F.Cu")
		(net "M_A_CPU1_SA_DQ<5>")
	)
	(segment
		(start 56.37911 -308.23408)
		(end 56.395874 -308.23408)
		(width 0.101854)
		(layer "F.Cu")
		(net "M_A_CPU1_SA_DQ<5>")
	)
	(segment
		(start 86.375494 -276.172676)
		(end 86.36 -276.18817)
		(width 0.088646)
		(layer "F.Cu")
		(net "M_A_CPU1_SA_DQ<5>")
	)
	(segment
		(start 76.034646 -300.503082)
		(end 73.135998 -300.503082)
		(width 0.20066)
		(layer "F.Cu")
		(net "M_A_CPU1_SA_DQ<5>")
	)
	(segment
		(start 81.795112 -294.742616)
		(end 81.217262 -295.320466)
		(width 0.1016)
		(layer "F.Cu")
		(net "M_A_CPU1_SA_DQ<5>")
	)
	(segment
		(start 66.381884 -309.102252)
		(end 66.212212 -309.102252)
		(width 0.20066)
		(layer "F.Cu")
		(net "M_A_CPU1_SA_DQ<5>")
	)
	(segment
		(start 69.267832 -305.845464)
		(end 69.048884 -306.064412)
		(width 0.20066)
		(layer "F.Cu")
		(net "M_A_CPU1_SA_DQ<5>")
	)
	(segment
		(start 58.704226 -308.2417)
		(end 58.858912 -308.2417)
		(width 0.20066)
		(layer "F.Cu")
		(net "M_A_CPU1_SA_DQ<5>")
	)
	(segment
		(start 54.897528 -308.421786)
		(end 55.085234 -308.23408)
		(width 0.20066)
		(layer "F.Cu")
		(net "M_A_CPU1_SA_DQ<5>")
	)
	(segment
		(start 53.403246 -308.666642)
		(end 54.02707 -308.666642)
		(width 0.20066)
		(layer "F.Cu")
		(net "M_A_CPU1_SA_DQ<5>")
	)
	(segment
		(start 68.311776 -305.611276)
		(end 68.027804 -305.611276)
		(width 0.20066)
		(layer "F.Cu")
		(net "M_A_CPU1_SA_DQ<5>")
	)
	(segment
		(start 84.111084 -277.420832)
		(end 84.111084 -277.555706)
		(width 0.088646)
		(layer "F.Cu")
		(net "M_A_CPU1_SA_DQ<5>")
	)
	(segment
		(start 64.019176 -309.10784)
		(end 63.977012 -309.10784)
		(width 0.101854)
		(layer "F.Cu")
		(net "M_A_CPU1_SA_DQ<5>")
	)
	(segment
		(start 85.412072 -276.534626)
		(end 85.081364 -276.534626)
		(width 0.088646)
		(layer "F.Cu")
		(net "M_A_CPU1_SA_DQ<5>")
	)
	(segment
		(start 66.65214 -308.921658)
		(end 66.381884 -309.102252)
		(width 0.20066)
		(layer "F.Cu")
		(net "M_A_CPU1_SA_DQ<5>")
	)
	(segment
		(start 84.111084 -277.555706)
		(end 83.830922 -277.835868)
		(width 0.088646)
		(layer "F.Cu")
		(net "M_A_CPU1_SA_DQ<5>")
	)
	(segment
		(start 66.212212 -309.102252)
		(end 66.157856 -309.102252)
		(width 0.101854)
		(layer "F.Cu")
		(net "M_A_CPU1_SA_DQ<5>")
	)
	(segment
		(start 66.157856 -309.102252)
		(end 66.147188 -309.091584)
		(width 0.101854)
		(layer "F.Cu")
		(net "M_A_CPU1_SA_DQ<5>")
	)
	(segment
		(start 54.027324 -308.666388)
		(end 54.279292 -308.918356)
		(width 0.20066)
		(layer "F.Cu")
		(net "M_A_CPU1_SA_DQ<5>")
	)
	(segment
		(start 66.147188 -309.091584)
		(end 64.035432 -309.091584)
		(width 0.1016)
		(layer "F.Cu")
		(net "M_A_CPU1_SA_DQ<5>")
	)
	(segment
		(start 83.830922 -277.835868)
		(end 83.465416 -277.835868)
		(width 0.088646)
		(layer "F.Cu")
		(net "M_A_CPU1_SA_DQ<5>")
	)
	(segment
		(start 66.653918 -308.911752)
		(end 66.65214 -308.921658)
		(width 0.20066)
		(layer "F.Cu")
		(net "M_A_CPU1_SA_DQ<5>")
	)
	(segment
		(start 54.897528 -308.684168)
		(end 54.897528 -308.421786)
		(width 0.20066)
		(layer "F.Cu")
		(net "M_A_CPU1_SA_DQ<5>")
	)
	(segment
		(start 81.217262 -295.320466)
		(end 76.034646 -300.503082)
		(width 0.20066)
		(layer "F.Cu")
		(net "M_A_CPU1_SA_DQ<5>")
	)
	(segment
		(start 63.977012 -309.10784)
		(end 63.20536 -309.10784)
		(width 0.20066)
		(layer "F.Cu")
		(net "M_A_CPU1_SA_DQ<5>")
	)
	(segment
		(start 62.764162 -308.666642)
		(end 60.947046 -308.666642)
		(width 0.20066)
		(layer "F.Cu")
		(net "M_A_CPU1_SA_DQ<5>")
	)
	(segment
		(start 56.403494 -308.2417)
		(end 56.433212 -308.2417)
		(width 0.101854)
		(layer "F.Cu")
		(net "M_A_CPU1_SA_DQ<5>")
	)
	(segment
		(start 55.085234 -308.23408)
		(end 56.37911 -308.23408)
		(width 0.20066)
		(layer "F.Cu")
		(net "M_A_CPU1_SA_DQ<5>")
	)
	(segment
		(start 81.795112 -281.9781)
		(end 81.795112 -294.742616)
		(width 0.1016)
		(layer "F.Cu")
		(net "M_A_CPU1_SA_DQ<5>")
	)
	(segment
		(start 54.279292 -308.918356)
		(end 54.66334 -308.918356)
		(width 0.20066)
		(layer "F.Cu")
		(net "M_A_CPU1_SA_DQ<5>")
	)
	(segment
		(start 58.858912 -308.2417)
		(end 59.283854 -308.666642)
		(width 0.20066)
		(layer "F.Cu")
		(net "M_A_CPU1_SA_DQ<5>")
	)
	(segment
		(start 69.267832 -305.561492)
		(end 69.267832 -305.845464)
		(width 0.20066)
		(layer "F.Cu")
		(net "M_A_CPU1_SA_DQ<5>")
	)
	(segment
		(start 59.283854 -308.666642)
		(end 60.947046 -308.666642)
		(width 0.20066)
		(layer "F.Cu")
		(net "M_A_CPU1_SA_DQ<5>")
	)
	(segment
		(start 68.814696 -304.824384)
		(end 68.814696 -305.108356)
		(width 0.20066)
		(layer "F.Cu")
		(net "M_A_CPU1_SA_DQ<5>")
	)
	(segment
		(start 56.395874 -308.23408)
		(end 56.403494 -308.2417)
		(width 0.101854)
		(layer "F.Cu")
		(net "M_A_CPU1_SA_DQ<5>")
	)
	(segment
		(start 56.433212 -308.2417)
		(end 58.643012 -308.2417)
		(width 0.1016)
		(layer "F.Cu")
		(net "M_A_CPU1_SA_DQ<5>")
	)
	(segment
		(start 64.035432 -309.091584)
		(end 64.019176 -309.10784)
		(width 0.101854)
		(layer "F.Cu")
		(net "M_A_CPU1_SA_DQ<5>")
	)
	(segment
		(start 58.643012 -308.2417)
		(end 58.704226 -308.2417)
		(width 0.101854)
		(layer "F.Cu")
		(net "M_A_CPU1_SA_DQ<5>")
	)
	(segment
		(start 73.135998 -300.503082)
		(end 68.814696 -304.824384)
		(width 0.20066)
		(layer "F.Cu")
		(net "M_A_CPU1_SA_DQ<5>")
	)
	(segment
		(start 68.764912 -306.064412)
		(end 68.311776 -305.611276)
		(width 0.20066)
		(layer "F.Cu")
		(net "M_A_CPU1_SA_DQ<5>")
	)
	(segment
		(start 69.048884 -306.064412)
		(end 68.764912 -306.064412)
		(width 0.20066)
		(layer "F.Cu")
		(net "M_A_CPU1_SA_DQ<5>")
	)
	(segment
		(start 67.865498 -305.773582)
		(end 67.865498 -307.269642)
		(width 0.20066)
		(layer "F.Cu")
		(net "M_A_CPU1_SA_DQ<5>")
	)
	(segment
		(start 83.14944 -278.151844)
		(end 82.414364 -278.88692)
		(width 0.1016)
		(layer "F.Cu")
		(net "M_A_CPU1_SA_DQ<5>")
	)
	(segment
		(start 54.66334 -308.918356)
		(end 54.897528 -308.684168)
		(width 0.20066)
		(layer "F.Cu")
		(net "M_A_CPU1_SA_DQ<5>")
	)
	(segment
		(start 54.02707 -308.666642)
		(end 54.027324 -308.666388)
		(width 0.20066)
		(layer "F.Cu")
		(net "M_A_CPU1_SA_DQ<5>")
	)
	(segment
		(start 66.655442 -308.903116)
		(end 66.653918 -308.911752)
		(width 0.20066)
		(layer "F.Cu")
		(net "M_A_CPU1_SA_DQ<5>")
	)
	(segment
		(start 83.465416 -277.835868)
		(end 83.14944 -278.151844)
		(width 0.088646)
		(layer "F.Cu")
		(net "M_A_CPU1_SA_DQ<5>")
	)
	(segment
		(start 67.865498 -307.269642)
		(end 66.655442 -308.479698)
		(width 0.20066)
		(layer "F.Cu")
		(net "M_A_CPU1_SA_DQ<5>")
	)
	(segment
		(start 68.027804 -305.611276)
		(end 67.865498 -305.773582)
		(width 0.20066)
		(layer "F.Cu")
		(net "M_A_CPU1_SA_DQ<5>")
	)
	(segment
		(start 84.95919 -276.572726)
		(end 84.111084 -277.420832)
		(width 0.088646)
		(layer "F.Cu")
		(net "M_A_CPU1_SA_DQ<5>")
	)
	(segment
		(start 63.20536 -309.10784)
		(end 62.764162 -308.666642)
		(width 0.20066)
		(layer "F.Cu")
		(net "M_A_CPU1_SA_DQ<5>")
	)
	(segment
		(start 66.655442 -308.479698)
		(end 66.655442 -308.903116)
		(width 0.20066)
		(layer "F.Cu")
		(net "M_A_CPU1_SA_DQ<5>")
	)
	(arc
		(start 85.904578 -276.404832)
		(mid 85.862287 -276.418646)
		(end 85.818726 -276.427692)
		(width 0.088646)
		(layer "F.Cu")
		(net "M_A_CPU1_SA_DQ<5>")
	)
	(arc
		(start 85.081364 -276.534626)
		(mid 85.029791 -276.540233)
		(end 84.98078 -276.557232)
		(width 0.088646)
		(layer "F.Cu")
		(net "M_A_CPU1_SA_DQ<5>")
	)
	(arc
		(start 84.98078 -276.557232)
		(mid 84.969326 -276.564062)
		(end 84.95919 -276.572726)
		(width 0.088646)
		(layer "F.Cu")
		(net "M_A_CPU1_SA_DQ<5>")
	)
	(arc
		(start 85.658706 -276.47773)
		(mid 85.538616 -276.520166)
		(end 85.412072 -276.534626)
		(width 0.088646)
		(layer "F.Cu")
		(net "M_A_CPU1_SA_DQ<5>")
	)
	(arc
		(start 86.36 -276.18817)
		(mid 86.135941 -276.304178)
		(end 85.904578 -276.404832)
		(width 0.088646)
		(layer "F.Cu")
		(net "M_A_CPU1_SA_DQ<5>")
	)
	(arc
		(start 85.818726 -276.427692)
		(mid 85.736853 -276.446751)
		(end 85.658706 -276.47773)
		(width 0.088646)
		(layer "F.Cu")
		(net "M_A_CPU1_SA_DQ<5>")
	)
	(segment
		(start 75.591162 -302.327564)
		(end 75.869038 -302.382936)
		(width 0.20066)
		(layer "F.Cu")
		(net "M_A_CPU1_SA_DQ<4>")
	)
	(segment
		(start 75.869038 -302.382936)
		(end 76.158852 -302.189134)
		(width 0.20066)
		(layer "F.Cu")
		(net "M_A_CPU1_SA_DQ<4>")
	)
	(segment
		(start 54.279292 -310.618378)
		(end 54.66334 -310.618378)
		(width 0.20066)
		(layer "F.Cu")
		(net "M_A_CPU1_SA_DQ<4>")
	)
	(segment
		(start 73.610216 -302.842676)
		(end 73.86828 -302.67021)
		(width 0.20066)
		(layer "F.Cu")
		(net "M_A_CPU1_SA_DQ<4>")
	)
	(segment
		(start 81.626964 -296.721022)
		(end 82.15376 -296.194226)
		(width 0.1016)
		(layer "F.Cu")
		(net "M_A_CPU1_SA_DQ<4>")
	)
	(segment
		(start 64.026034 -309.927244)
		(end 64.040512 -309.941722)
		(width 0.101854)
		(layer "F.Cu")
		(net "M_A_CPU1_SA_DQ<4>")
	)
	(segment
		(start 83.591146 -278.593296)
		(end 83.935316 -278.249126)
		(width 0.088646)
		(layer "F.Cu")
		(net "M_A_CPU1_SA_DQ<4>")
	)
	(segment
		(start 63.977012 -309.927244)
		(end 64.026034 -309.927244)
		(width 0.101854)
		(layer "F.Cu")
		(net "M_A_CPU1_SA_DQ<4>")
	)
	(segment
		(start 54.02707 -310.366664)
		(end 54.027324 -310.36641)
		(width 0.20066)
		(layer "F.Cu")
		(net "M_A_CPU1_SA_DQ<4>")
	)
	(segment
		(start 54.027324 -310.36641)
		(end 54.279292 -310.618378)
		(width 0.20066)
		(layer "F.Cu")
		(net "M_A_CPU1_SA_DQ<4>")
	)
	(segment
		(start 74.79284 -302.052228)
		(end 75.050904 -301.879762)
		(width 0.20066)
		(layer "F.Cu")
		(net "M_A_CPU1_SA_DQ<4>")
	)
	(segment
		(start 55.11673 -309.902606)
		(end 56.37911 -309.902606)
		(width 0.20066)
		(layer "F.Cu")
		(net "M_A_CPU1_SA_DQ<4>")
	)
	(segment
		(start 64.040512 -309.941722)
		(end 66.104516 -309.941722)
		(width 0.1016)
		(layer "F.Cu")
		(net "M_A_CPU1_SA_DQ<4>")
	)
	(segment
		(start 75.050904 -301.879762)
		(end 75.32878 -301.935134)
		(width 0.20066)
		(layer "F.Cu")
		(net "M_A_CPU1_SA_DQ<4>")
	)
	(segment
		(start 56.458612 -309.941722)
		(end 58.617612 -309.941722)
		(width 0.1016)
		(layer "F.Cu")
		(net "M_A_CPU1_SA_DQ<4>")
	)
	(segment
		(start 58.617612 -309.941722)
		(end 58.704226 -309.941722)
		(width 0.101854)
		(layer "F.Cu")
		(net "M_A_CPU1_SA_DQ<4>")
	)
	(segment
		(start 60.004706 -310.366664)
		(end 60.947046 -310.366664)
		(width 0.20066)
		(layer "F.Cu")
		(net "M_A_CPU1_SA_DQ<4>")
	)
	(segment
		(start 61.775086 -310.366664)
		(end 62.922404 -310.115966)
		(width 0.20066)
		(layer "F.Cu")
		(net "M_A_CPU1_SA_DQ<4>")
	)
	(segment
		(start 59.215782 -310.139842)
		(end 59.777884 -310.139842)
		(width 0.20066)
		(layer "F.Cu")
		(net "M_A_CPU1_SA_DQ<4>")
	)
	(segment
		(start 60.947046 -310.366664)
		(end 61.775086 -310.366664)
		(width 0.20066)
		(layer "F.Cu")
		(net "M_A_CPU1_SA_DQ<4>")
	)
	(segment
		(start 82.15376 -296.194226)
		(end 82.404712 -295.588182)
		(width 0.1016)
		(layer "F.Cu")
		(net "M_A_CPU1_SA_DQ<4>")
	)
	(segment
		(start 73.255124 -304.129694)
		(end 73.761854 -303.791112)
		(width 0.20066)
		(layer "F.Cu")
		(net "M_A_CPU1_SA_DQ<4>")
	)
	(segment
		(start 59.017662 -309.941722)
		(end 59.215782 -310.139842)
		(width 0.20066)
		(layer "F.Cu")
		(net "M_A_CPU1_SA_DQ<4>")
	)
	(segment
		(start 76.158852 -302.189134)
		(end 81.626964 -296.721022)
		(width 0.20066)
		(layer "F.Cu")
		(net "M_A_CPU1_SA_DQ<4>")
	)
	(segment
		(start 66.104516 -309.941722)
		(end 66.120264 -309.925974)
		(width 0.101854)
		(layer "F.Cu")
		(net "M_A_CPU1_SA_DQ<4>")
	)
	(segment
		(start 58.704226 -309.941722)
		(end 59.017662 -309.941722)
		(width 0.20066)
		(layer "F.Cu")
		(net "M_A_CPU1_SA_DQ<4>")
	)
	(segment
		(start 74.944478 -303.000918)
		(end 74.99985 -302.722788)
		(width 0.20066)
		(layer "F.Cu")
		(net "M_A_CPU1_SA_DQ<4>")
	)
	(segment
		(start 66.656458 -309.925974)
		(end 66.902838 -310.172354)
		(width 0.20066)
		(layer "F.Cu")
		(net "M_A_CPU1_SA_DQ<4>")
	)
	(segment
		(start 56.390794 -309.902606)
		(end 56.42991 -309.941722)
		(width 0.101854)
		(layer "F.Cu")
		(net "M_A_CPU1_SA_DQ<4>")
	)
	(segment
		(start 54.897528 -310.38419)
		(end 54.897528 -310.121808)
		(width 0.20066)
		(layer "F.Cu")
		(net "M_A_CPU1_SA_DQ<4>")
	)
	(segment
		(start 73.761854 -303.791112)
		(end 73.817226 -303.513236)
		(width 0.20066)
		(layer "F.Cu")
		(net "M_A_CPU1_SA_DQ<4>")
	)
	(segment
		(start 83.935316 -278.249126)
		(end 83.963256 -278.249126)
		(width 0.088646)
		(layer "F.Cu")
		(net "M_A_CPU1_SA_DQ<4>")
	)
	(segment
		(start 53.403246 -310.366664)
		(end 54.02707 -310.366664)
		(width 0.20066)
		(layer "F.Cu")
		(net "M_A_CPU1_SA_DQ<4>")
	)
	(segment
		(start 82.404712 -295.588182)
		(end 82.404712 -282.041854)
		(width 0.1016)
		(layer "F.Cu")
		(net "M_A_CPU1_SA_DQ<4>")
	)
	(segment
		(start 74.686414 -303.173384)
		(end 74.944478 -303.000918)
		(width 0.20066)
		(layer "F.Cu")
		(net "M_A_CPU1_SA_DQ<4>")
	)
	(segment
		(start 74.99985 -302.722788)
		(end 74.737468 -302.330358)
		(width 0.20066)
		(layer "F.Cu")
		(net "M_A_CPU1_SA_DQ<4>")
	)
	(segment
		(start 54.897528 -310.121808)
		(end 55.11673 -309.902606)
		(width 0.20066)
		(layer "F.Cu")
		(net "M_A_CPU1_SA_DQ<4>")
	)
	(segment
		(start 82.404712 -282.041854)
		(end 82.971132 -279.21331)
		(width 0.1016)
		(layer "F.Cu")
		(net "M_A_CPU1_SA_DQ<4>")
	)
	(segment
		(start 59.777884 -310.139842)
		(end 60.004706 -310.366664)
		(width 0.20066)
		(layer "F.Cu")
		(net "M_A_CPU1_SA_DQ<4>")
	)
	(segment
		(start 66.902838 -310.172354)
		(end 67.212464 -310.172354)
		(width 0.20066)
		(layer "F.Cu")
		(net "M_A_CPU1_SA_DQ<4>")
	)
	(segment
		(start 73.554844 -303.120806)
		(end 73.610216 -302.842676)
		(width 0.20066)
		(layer "F.Cu")
		(net "M_A_CPU1_SA_DQ<4>")
	)
	(segment
		(start 84.499704 -277.712678)
		(end 84.499704 -277.570692)
		(width 0.088646)
		(layer "F.Cu")
		(net "M_A_CPU1_SA_DQ<4>")
	)
	(segment
		(start 74.737468 -302.330358)
		(end 74.79284 -302.052228)
		(width 0.20066)
		(layer "F.Cu")
		(net "M_A_CPU1_SA_DQ<4>")
	)
	(segment
		(start 56.42991 -309.941722)
		(end 56.458612 -309.941722)
		(width 0.101854)
		(layer "F.Cu")
		(net "M_A_CPU1_SA_DQ<4>")
	)
	(segment
		(start 73.86828 -302.67021)
		(end 74.146156 -302.725582)
		(width 0.20066)
		(layer "F.Cu")
		(net "M_A_CPU1_SA_DQ<4>")
	)
	(segment
		(start 63.478156 -309.927244)
		(end 63.977012 -309.927244)
		(width 0.20066)
		(layer "F.Cu")
		(net "M_A_CPU1_SA_DQ<4>")
	)
	(segment
		(start 73.817226 -303.513236)
		(end 73.554844 -303.120806)
		(width 0.20066)
		(layer "F.Cu")
		(net "M_A_CPU1_SA_DQ<4>")
	)
	(segment
		(start 66.120264 -309.925974)
		(end 66.186812 -309.925974)
		(width 0.101854)
		(layer "F.Cu")
		(net "M_A_CPU1_SA_DQ<4>")
	)
	(segment
		(start 56.37911 -309.902606)
		(end 56.390794 -309.902606)
		(width 0.101854)
		(layer "F.Cu")
		(net "M_A_CPU1_SA_DQ<4>")
	)
	(segment
		(start 74.146156 -302.725582)
		(end 74.408538 -303.118012)
		(width 0.20066)
		(layer "F.Cu")
		(net "M_A_CPU1_SA_DQ<4>")
	)
	(segment
		(start 85.083904 -276.986492)
		(end 85.905594 -276.986492)
		(width 0.088646)
		(layer "F.Cu")
		(net "M_A_CPU1_SA_DQ<4>")
	)
	(segment
		(start 75.32878 -301.935134)
		(end 75.591162 -302.327564)
		(width 0.20066)
		(layer "F.Cu")
		(net "M_A_CPU1_SA_DQ<4>")
	)
	(segment
		(start 54.66334 -310.618378)
		(end 54.897528 -310.38419)
		(width 0.20066)
		(layer "F.Cu")
		(net "M_A_CPU1_SA_DQ<4>")
	)
	(segment
		(start 62.922404 -310.115966)
		(end 63.478156 -309.927244)
		(width 0.20066)
		(layer "F.Cu")
		(net "M_A_CPU1_SA_DQ<4>")
	)
	(segment
		(start 74.408538 -303.118012)
		(end 74.686414 -303.173384)
		(width 0.20066)
		(layer "F.Cu")
		(net "M_A_CPU1_SA_DQ<4>")
	)
	(segment
		(start 82.971132 -279.21331)
		(end 83.591146 -278.593296)
		(width 0.1016)
		(layer "F.Cu")
		(net "M_A_CPU1_SA_DQ<4>")
	)
	(segment
		(start 67.212464 -310.172354)
		(end 73.255124 -304.129694)
		(width 0.20066)
		(layer "F.Cu")
		(net "M_A_CPU1_SA_DQ<4>")
	)
	(segment
		(start 66.186812 -309.925974)
		(end 66.656458 -309.925974)
		(width 0.20066)
		(layer "F.Cu")
		(net "M_A_CPU1_SA_DQ<4>")
	)
	(segment
		(start 83.963256 -278.249126)
		(end 84.499704 -277.712678)
		(width 0.088646)
		(layer "F.Cu")
		(net "M_A_CPU1_SA_DQ<4>")
	)
	(segment
		(start 84.499704 -277.570692)
		(end 85.083904 -276.986492)
		(width 0.088646)
		(layer "F.Cu")
		(net "M_A_CPU1_SA_DQ<4>")
	)
	(segment
		(start 74.781664 -306.931314)
		(end 75.284584 -306.428394)
		(width 0.20066)
		(layer "F.Cu")
		(net "M_A_CPU1_SA_DQ<3>")
	)
	(segment
		(start 83.307428 -298.689522)
		(end 83.307428 -298.534582)
		(width 0.1016)
		(layer "F.Cu")
		(net "M_A_CPU1_SA_DQ<3>")
	)
	(segment
		(start 85.198204 -279.086056)
		(end 85.549486 -279.086056)
		(width 0.088646)
		(layer "F.Cu")
		(net "M_A_CPU1_SA_DQ<3>")
	)
	(segment
		(start 73.17613 -308.3433)
		(end 73.272904 -308.440074)
		(width 0.20066)
		(layer "F.Cu")
		(net "M_A_CPU1_SA_DQ<3>")
	)
	(segment
		(start 59.887612 -314.19165)
		(end 62.072012 -314.19165)
		(width 0.1016)
		(layer "F.Cu")
		(net "M_A_CPU1_SA_DQ<3>")
	)
	(segment
		(start 65.047114 -313.766708)
		(end 65.471802 -313.766708)
		(width 0.20066)
		(layer "F.Cu")
		(net "M_A_CPU1_SA_DQ<3>")
	)
	(segment
		(start 71.764144 -309.948834)
		(end 71.666354 -309.851044)
		(width 0.20066)
		(layer "F.Cu")
		(net "M_A_CPU1_SA_DQ<3>")
	)
	(segment
		(start 68.50761 -312.748168)
		(end 68.837048 -312.52795)
		(width 0.20066)
		(layer "F.Cu")
		(net "M_A_CPU1_SA_DQ<3>")
	)
	(segment
		(start 69.752464 -312.244486)
		(end 69.752464 -311.960514)
		(width 0.20066)
		(layer "F.Cu")
		(net "M_A_CPU1_SA_DQ<3>")
	)
	(segment
		(start 72.892158 -308.3433)
		(end 73.17613 -308.3433)
		(width 0.20066)
		(layer "F.Cu")
		(net "M_A_CPU1_SA_DQ<3>")
	)
	(segment
		(start 87.095584 -278.881078)
		(end 87.329264 -278.647398)
		(width 0.088646)
		(layer "F.Cu")
		(net "M_A_CPU1_SA_DQ<3>")
	)
	(segment
		(start 59.184794 -313.766708)
		(end 59.609736 -314.19165)
		(width 0.20066)
		(layer "F.Cu")
		(net "M_A_CPU1_SA_DQ<3>")
	)
	(segment
		(start 62.147958 -314.199524)
		(end 62.473078 -314.199524)
		(width 0.20066)
		(layer "F.Cu")
		(net "M_A_CPU1_SA_DQ<3>")
	)
	(segment
		(start 85.00491 -279.27935)
		(end 85.198204 -279.086056)
		(width 0.088646)
		(layer "F.Cu")
		(net "M_A_CPU1_SA_DQ<3>")
	)
	(segment
		(start 70.758304 -310.954674)
		(end 70.660514 -310.856884)
		(width 0.20066)
		(layer "F.Cu")
		(net "M_A_CPU1_SA_DQ<3>")
	)
	(segment
		(start 73.556876 -308.440074)
		(end 73.775824 -308.221126)
		(width 0.20066)
		(layer "F.Cu")
		(net "M_A_CPU1_SA_DQ<3>")
	)
	(segment
		(start 62.072012 -314.19165)
		(end 62.094618 -314.19165)
		(width 0.101854)
		(layer "F.Cu")
		(net "M_A_CPU1_SA_DQ<3>")
	)
	(segment
		(start 65.693036 -313.987942)
		(end 66.662554 -313.987942)
		(width 0.20066)
		(layer "F.Cu")
		(net "M_A_CPU1_SA_DQ<3>")
	)
	(segment
		(start 70.879462 -310.353964)
		(end 71.163434 -310.353964)
		(width 0.20066)
		(layer "F.Cu")
		(net "M_A_CPU1_SA_DQ<3>")
	)
	(segment
		(start 71.545196 -310.451754)
		(end 71.764144 -310.232806)
		(width 0.20066)
		(layer "F.Cu")
		(net "M_A_CPU1_SA_DQ<3>")
	)
	(segment
		(start 70.255384 -311.457594)
		(end 70.539356 -311.457594)
		(width 0.20066)
		(layer "F.Cu")
		(net "M_A_CPU1_SA_DQ<3>")
	)
	(segment
		(start 62.473078 -314.199524)
		(end 62.97168 -313.700922)
		(width 0.20066)
		(layer "F.Cu")
		(net "M_A_CPU1_SA_DQ<3>")
	)
	(segment
		(start 74.781664 -307.215286)
		(end 74.781664 -306.931314)
		(width 0.20066)
		(layer "F.Cu")
		(net "M_A_CPU1_SA_DQ<3>")
	)
	(segment
		(start 83.928712 -297.034204)
		(end 83.928712 -282.453588)
		(width 0.1016)
		(layer "F.Cu")
		(net "M_A_CPU1_SA_DQ<3>")
	)
	(segment
		(start 75.284584 -306.428394)
		(end 75.568556 -306.428394)
		(width 0.20066)
		(layer "F.Cu")
		(net "M_A_CPU1_SA_DQ<3>")
	)
	(segment
		(start 70.157594 -311.359804)
		(end 70.255384 -311.457594)
		(width 0.20066)
		(layer "F.Cu")
		(net "M_A_CPU1_SA_DQ<3>")
	)
	(segment
		(start 68.127626 -313.381136)
		(end 68.420996 -313.185302)
		(width 0.20066)
		(layer "F.Cu")
		(net "M_A_CPU1_SA_DQ<3>")
	)
	(segment
		(start 59.609736 -314.19165)
		(end 59.822842 -314.19165)
		(width 0.20066)
		(layer "F.Cu")
		(net "M_A_CPU1_SA_DQ<3>")
	)
	(segment
		(start 64.08166 -314.150502)
		(end 64.465454 -313.766708)
		(width 0.20066)
		(layer "F.Cu")
		(net "M_A_CPU1_SA_DQ<3>")
	)
	(segment
		(start 70.660514 -310.856884)
		(end 70.660514 -310.572912)
		(width 0.20066)
		(layer "F.Cu")
		(net "M_A_CPU1_SA_DQ<3>")
	)
	(segment
		(start 87.40902 -278.614378)
		(end 87.785194 -278.614378)
		(width 0.088646)
		(layer "F.Cu")
		(net "M_A_CPU1_SA_DQ<3>")
	)
	(segment
		(start 73.775824 -308.221126)
		(end 73.775824 -307.937154)
		(width 0.20066)
		(layer "F.Cu")
		(net "M_A_CPU1_SA_DQ<3>")
	)
	(segment
		(start 69.752464 -311.960514)
		(end 69.654674 -311.862724)
		(width 0.20066)
		(layer "F.Cu")
		(net "M_A_CPU1_SA_DQ<3>")
	)
	(segment
		(start 68.837048 -312.52795)
		(end 69.274182 -312.614818)
		(width 0.20066)
		(layer "F.Cu")
		(net "M_A_CPU1_SA_DQ<3>")
	)
	(segment
		(start 72.67321 -308.84622)
		(end 72.67321 -308.562248)
		(width 0.20066)
		(layer "F.Cu")
		(net "M_A_CPU1_SA_DQ<3>")
	)
	(segment
		(start 83.928712 -282.453588)
		(end 84.425536 -279.970484)
		(width 0.1016)
		(layer "F.Cu")
		(net "M_A_CPU1_SA_DQ<3>")
	)
	(segment
		(start 66.662554 -313.987942)
		(end 66.977514 -313.857386)
		(width 0.20066)
		(layer "F.Cu")
		(net "M_A_CPU1_SA_DQ<3>")
	)
	(segment
		(start 71.885302 -309.348124)
		(end 72.169274 -309.348124)
		(width 0.20066)
		(layer "F.Cu")
		(net "M_A_CPU1_SA_DQ<3>")
	)
	(segment
		(start 71.666354 -309.851044)
		(end 71.666354 -309.567072)
		(width 0.20066)
		(layer "F.Cu")
		(net "M_A_CPU1_SA_DQ<3>")
	)
	(segment
		(start 70.660514 -310.572912)
		(end 70.879462 -310.353964)
		(width 0.20066)
		(layer "F.Cu")
		(net "M_A_CPU1_SA_DQ<3>")
	)
	(segment
		(start 72.769984 -308.942994)
		(end 72.67321 -308.84622)
		(width 0.20066)
		(layer "F.Cu")
		(net "M_A_CPU1_SA_DQ<3>")
	)
	(segment
		(start 84.425536 -279.970484)
		(end 84.735162 -279.660858)
		(width 0.1016)
		(layer "F.Cu")
		(net "M_A_CPU1_SA_DQ<3>")
	)
	(segment
		(start 69.654674 -311.862724)
		(end 69.654674 -311.578752)
		(width 0.20066)
		(layer "F.Cu")
		(net "M_A_CPU1_SA_DQ<3>")
	)
	(segment
		(start 63.276226 -313.700922)
		(end 63.725806 -314.150502)
		(width 0.20066)
		(layer "F.Cu")
		(net "M_A_CPU1_SA_DQ<3>")
	)
	(segment
		(start 75.568556 -306.428394)
		(end 83.1977 -298.79925)
		(width 0.20066)
		(layer "F.Cu")
		(net "M_A_CPU1_SA_DQ<3>")
	)
	(segment
		(start 72.551036 -309.445914)
		(end 72.769984 -309.226966)
		(width 0.20066)
		(layer "F.Cu")
		(net "M_A_CPU1_SA_DQ<3>")
	)
	(segment
		(start 73.777348 -307.93563)
		(end 73.777348 -307.653182)
		(width 0.20066)
		(layer "F.Cu")
		(net "M_A_CPU1_SA_DQ<3>")
	)
	(segment
		(start 65.471802 -313.766708)
		(end 65.693036 -313.987942)
		(width 0.20066)
		(layer "F.Cu")
		(net "M_A_CPU1_SA_DQ<3>")
	)
	(segment
		(start 62.102492 -314.199524)
		(end 62.147958 -314.199524)
		(width 0.101854)
		(layer "F.Cu")
		(net "M_A_CPU1_SA_DQ<3>")
	)
	(segment
		(start 86.092792 -278.938736)
		(end 86.103206 -278.93264)
		(width 0.088646)
		(layer "F.Cu")
		(net "M_A_CPU1_SA_DQ<3>")
	)
	(segment
		(start 70.758304 -311.238646)
		(end 70.758304 -310.954674)
		(width 0.20066)
		(layer "F.Cu")
		(net "M_A_CPU1_SA_DQ<3>")
	)
	(segment
		(start 74.544682 -307.452268)
		(end 74.781664 -307.215286)
		(width 0.20066)
		(layer "F.Cu")
		(net "M_A_CPU1_SA_DQ<3>")
	)
	(segment
		(start 83.307428 -298.534582)
		(end 83.928712 -297.034204)
		(width 0.1016)
		(layer "F.Cu")
		(net "M_A_CPU1_SA_DQ<3>")
	)
	(segment
		(start 59.822842 -314.19165)
		(end 59.887612 -314.19165)
		(width 0.101854)
		(layer "F.Cu")
		(net "M_A_CPU1_SA_DQ<3>")
	)
	(segment
		(start 69.599556 -312.397394)
		(end 69.752464 -312.244486)
		(width 0.20066)
		(layer "F.Cu")
		(net "M_A_CPU1_SA_DQ<3>")
	)
	(segment
		(start 64.465454 -313.766708)
		(end 65.047114 -313.766708)
		(width 0.20066)
		(layer "F.Cu")
		(net "M_A_CPU1_SA_DQ<3>")
	)
	(segment
		(start 73.775824 -307.937154)
		(end 73.777348 -307.93563)
		(width 0.20066)
		(layer "F.Cu")
		(net "M_A_CPU1_SA_DQ<3>")
	)
	(segment
		(start 70.539356 -311.457594)
		(end 70.758304 -311.238646)
		(width 0.20066)
		(layer "F.Cu")
		(net "M_A_CPU1_SA_DQ<3>")
	)
	(segment
		(start 73.978262 -307.452268)
		(end 74.544682 -307.452268)
		(width 0.20066)
		(layer "F.Cu")
		(net "M_A_CPU1_SA_DQ<3>")
	)
	(segment
		(start 73.777348 -307.653182)
		(end 73.978262 -307.452268)
		(width 0.20066)
		(layer "F.Cu")
		(net "M_A_CPU1_SA_DQ<3>")
	)
	(segment
		(start 73.272904 -308.440074)
		(end 73.556876 -308.440074)
		(width 0.20066)
		(layer "F.Cu")
		(net "M_A_CPU1_SA_DQ<3>")
	)
	(segment
		(start 62.97168 -313.700922)
		(end 63.276226 -313.700922)
		(width 0.20066)
		(layer "F.Cu")
		(net "M_A_CPU1_SA_DQ<3>")
	)
	(segment
		(start 72.769984 -309.226966)
		(end 72.769984 -308.942994)
		(width 0.20066)
		(layer "F.Cu")
		(net "M_A_CPU1_SA_DQ<3>")
	)
	(segment
		(start 83.1977 -298.79925)
		(end 83.307428 -298.689522)
		(width 0.1016)
		(layer "F.Cu")
		(net "M_A_CPU1_SA_DQ<3>")
	)
	(segment
		(start 72.169274 -309.348124)
		(end 72.267064 -309.445914)
		(width 0.20066)
		(layer "F.Cu")
		(net "M_A_CPU1_SA_DQ<3>")
	)
	(segment
		(start 66.977514 -313.857386)
		(end 68.127626 -313.381136)
		(width 0.20066)
		(layer "F.Cu")
		(net "M_A_CPU1_SA_DQ<3>")
	)
	(segment
		(start 68.420996 -313.185302)
		(end 68.50761 -312.748168)
		(width 0.20066)
		(layer "F.Cu")
		(net "M_A_CPU1_SA_DQ<3>")
	)
	(segment
		(start 69.873622 -311.359804)
		(end 70.157594 -311.359804)
		(width 0.20066)
		(layer "F.Cu")
		(net "M_A_CPU1_SA_DQ<3>")
	)
	(segment
		(start 57.503314 -313.766708)
		(end 59.184794 -313.766708)
		(width 0.20066)
		(layer "F.Cu")
		(net "M_A_CPU1_SA_DQ<3>")
	)
	(segment
		(start 72.67321 -308.562248)
		(end 72.892158 -308.3433)
		(width 0.20066)
		(layer "F.Cu")
		(net "M_A_CPU1_SA_DQ<3>")
	)
	(segment
		(start 71.764144 -310.232806)
		(end 71.764144 -309.948834)
		(width 0.20066)
		(layer "F.Cu")
		(net "M_A_CPU1_SA_DQ<3>")
	)
	(segment
		(start 62.094618 -314.19165)
		(end 62.102492 -314.199524)
		(width 0.101854)
		(layer "F.Cu")
		(net "M_A_CPU1_SA_DQ<3>")
	)
	(segment
		(start 71.261224 -310.451754)
		(end 71.545196 -310.451754)
		(width 0.20066)
		(layer "F.Cu")
		(net "M_A_CPU1_SA_DQ<3>")
	)
	(segment
		(start 69.274182 -312.614818)
		(end 69.599556 -312.397394)
		(width 0.20066)
		(layer "F.Cu")
		(net "M_A_CPU1_SA_DQ<3>")
	)
	(segment
		(start 84.735162 -279.660858)
		(end 84.867242 -279.528778)
		(width 0.088646)
		(layer "F.Cu")
		(net "M_A_CPU1_SA_DQ<3>")
	)
	(segment
		(start 69.654674 -311.578752)
		(end 69.873622 -311.359804)
		(width 0.20066)
		(layer "F.Cu")
		(net "M_A_CPU1_SA_DQ<3>")
	)
	(segment
		(start 63.725806 -314.150502)
		(end 64.08166 -314.150502)
		(width 0.20066)
		(layer "F.Cu")
		(net "M_A_CPU1_SA_DQ<3>")
	)
	(segment
		(start 71.163434 -310.353964)
		(end 71.261224 -310.451754)
		(width 0.20066)
		(layer "F.Cu")
		(net "M_A_CPU1_SA_DQ<3>")
	)
	(segment
		(start 72.267064 -309.445914)
		(end 72.551036 -309.445914)
		(width 0.20066)
		(layer "F.Cu")
		(net "M_A_CPU1_SA_DQ<3>")
	)
	(segment
		(start 71.666354 -309.567072)
		(end 71.885302 -309.348124)
		(width 0.20066)
		(layer "F.Cu")
		(net "M_A_CPU1_SA_DQ<3>")
	)
	(arc
		(start 84.867242 -279.528778)
		(mid 84.910463 -279.471415)
		(end 84.936076 -279.404318)
		(width 0.088646)
		(layer "F.Cu")
		(net "M_A_CPU1_SA_DQ<3>")
	)
	(arc
		(start 86.65845 -278.938736)
		(mid 86.886833 -278.984161)
		(end 87.095584 -278.881078)
		(width 0.088646)
		(layer "F.Cu")
		(net "M_A_CPU1_SA_DQ<3>")
	)
	(arc
		(start 87.329264 -278.647398)
		(mid 87.365856 -278.622948)
		(end 87.40902 -278.614378)
		(width 0.088646)
		(layer "F.Cu")
		(net "M_A_CPU1_SA_DQ<3>")
	)
	(arc
		(start 84.936076 -279.404318)
		(mid 84.961633 -279.336954)
		(end 85.00491 -279.27935)
		(width 0.088646)
		(layer "F.Cu")
		(net "M_A_CPU1_SA_DQ<3>")
	)
	(arc
		(start 85.549486 -279.086056)
		(mid 85.830952 -279.048579)
		(end 86.092792 -278.938736)
		(width 0.088646)
		(layer "F.Cu")
		(net "M_A_CPU1_SA_DQ<3>")
	)
	(arc
		(start 86.103206 -278.93264)
		(mid 86.381638 -278.862794)
		(end 86.65845 -278.938736)
		(width 0.088646)
		(layer "F.Cu")
		(net "M_A_CPU1_SA_DQ<3>")
	)
	(segment
		(start 82.929222 -265.138662)
		(end 82.929222 -265.486134)
		(width 0.1016)
		(layer "F.Cu")
		(net "M_A_CPU1_SA_DQ<31>")
	)
	(segment
		(start 70.723506 -279.70861)
		(end 70.258178 -279.70861)
		(width 0.20066)
		(layer "F.Cu")
		(net "M_A_CPU1_SA_DQ<31>")
	)
	(segment
		(start 70.833742 -279.818846)
		(end 70.723506 -279.70861)
		(width 0.20066)
		(layer "F.Cu")
		(net "M_A_CPU1_SA_DQ<31>")
	)
	(segment
		(start 68.090542 -280.039826)
		(end 68.090542 -279.818846)
		(width 0.20066)
		(layer "F.Cu")
		(net "M_A_CPU1_SA_DQ<31>")
	)
	(segment
		(start 86.845648 -265.347958)
		(end 86.924388 -265.269218)
		(width 0.088646)
		(layer "F.Cu")
		(net "M_A_CPU1_SA_DQ<31>")
	)
	(segment
		(start 59.188604 -279.766776)
		(end 59.188858 -279.766522)
		(width 0.20066)
		(layer "F.Cu")
		(net "M_A_CPU1_SA_DQ<31>")
	)
	(segment
		(start 83.177888 -265.594592)
		(end 83.279488 -265.696192)
		(width 0.1016)
		(layer "F.Cu")
		(net "M_A_CPU1_SA_DQ<31>")
	)
	(segment
		(start 85.598762 -265.185906)
		(end 85.18271 -265.185906)
		(width 0.088646)
		(layer "F.Cu")
		(net "M_A_CPU1_SA_DQ<31>")
	)
	(segment
		(start 86.491826 -265.358626)
		(end 86.415626 -265.434826)
		(width 0.088646)
		(layer "F.Cu")
		(net "M_A_CPU1_SA_DQ<31>")
	)
	(segment
		(start 64.09182 -279.766776)
		(end 65.047114 -279.766776)
		(width 0.20066)
		(layer "F.Cu")
		(net "M_A_CPU1_SA_DQ<31>")
	)
	(segment
		(start 66.427858 -279.929336)
		(end 66.08699 -279.929336)
		(width 0.20066)
		(layer "F.Cu")
		(net "M_A_CPU1_SA_DQ<31>")
	)
	(segment
		(start 59.41695 -280.207974)
		(end 59.822842 -280.207974)
		(width 0.20066)
		(layer "F.Cu")
		(net "M_A_CPU1_SA_DQ<31>")
	)
	(segment
		(start 86.691724 -264.987532)
		(end 86.491826 -265.18743)
		(width 0.088646)
		(layer "F.Cu")
		(net "M_A_CPU1_SA_DQ<31>")
	)
	(segment
		(start 63.021464 -279.47112)
		(end 63.796164 -279.47112)
		(width 0.20066)
		(layer "F.Cu")
		(net "M_A_CPU1_SA_DQ<31>")
	)
	(segment
		(start 59.839098 -280.191718)
		(end 60.107068 -280.191718)
		(width 0.101854)
		(layer "F.Cu")
		(net "M_A_CPU1_SA_DQ<31>")
	)
	(segment
		(start 83.928204 -264.901934)
		(end 83.838288 -264.99185)
		(width 0.1016)
		(layer "F.Cu")
		(net "M_A_CPU1_SA_DQ<31>")
	)
	(segment
		(start 65.92443 -279.766776)
		(end 65.047114 -279.766776)
		(width 0.20066)
		(layer "F.Cu")
		(net "M_A_CPU1_SA_DQ<31>")
	)
	(segment
		(start 73.462642 -278.66975)
		(end 73.345802 -278.55291)
		(width 0.1016)
		(layer "F.Cu")
		(net "M_A_CPU1_SA_DQ<31>")
	)
	(segment
		(start 59.188858 -279.766522)
		(end 59.314842 -279.892506)
		(width 0.20066)
		(layer "F.Cu")
		(net "M_A_CPU1_SA_DQ<31>")
	)
	(segment
		(start 72.759824 -278.560022)
		(end 72.473058 -278.846788)
		(width 0.1016)
		(layer "F.Cu")
		(net "M_A_CPU1_SA_DQ<31>")
	)
	(segment
		(start 61.915548 -280.197306)
		(end 62.147958 -280.197306)
		(width 0.101854)
		(layer "F.Cu")
		(net "M_A_CPU1_SA_DQ<31>")
	)
	(segment
		(start 73.698608 -278.66975)
		(end 73.462642 -278.66975)
		(width 0.1016)
		(layer "F.Cu")
		(net "M_A_CPU1_SA_DQ<31>")
	)
	(segment
		(start 86.415626 -265.434826)
		(end 86.263226 -265.434826)
		(width 0.088646)
		(layer "F.Cu")
		(net "M_A_CPU1_SA_DQ<31>")
	)
	(segment
		(start 67.404742 -279.818846)
		(end 67.404742 -280.039826)
		(width 0.20066)
		(layer "F.Cu")
		(net "M_A_CPU1_SA_DQ<31>")
	)
	(segment
		(start 72.97674 -278.06015)
		(end 72.759824 -278.277066)
		(width 0.1016)
		(layer "F.Cu")
		(net "M_A_CPU1_SA_DQ<31>")
	)
	(segment
		(start 70.258178 -279.70861)
		(end 70.147942 -279.818846)
		(width 0.20066)
		(layer "F.Cu")
		(net "M_A_CPU1_SA_DQ<31>")
	)
	(segment
		(start 72.473058 -278.846788)
		(end 71.39051 -279.929336)
		(width 0.20066)
		(layer "F.Cu")
		(net "M_A_CPU1_SA_DQ<31>")
	)
	(segment
		(start 85.983826 -264.901426)
		(end 85.824822 -264.901426)
		(width 0.088646)
		(layer "F.Cu")
		(net "M_A_CPU1_SA_DQ<31>")
	)
	(segment
		(start 57.503314 -279.766776)
		(end 59.188604 -279.766776)
		(width 0.20066)
		(layer "F.Cu")
		(net "M_A_CPU1_SA_DQ<31>")
	)
	(segment
		(start 86.845648 -265.592306)
		(end 86.845648 -265.347958)
		(width 0.088646)
		(layer "F.Cu")
		(net "M_A_CPU1_SA_DQ<31>")
	)
	(segment
		(start 67.514978 -279.70861)
		(end 67.404742 -279.818846)
		(width 0.20066)
		(layer "F.Cu")
		(net "M_A_CPU1_SA_DQ<31>")
	)
	(segment
		(start 74.529442 -276.284436)
		(end 74.124312 -278.319992)
		(width 0.1016)
		(layer "F.Cu")
		(net "M_A_CPU1_SA_DQ<31>")
	)
	(segment
		(start 70.037706 -280.150062)
		(end 69.572378 -280.150062)
		(width 0.20066)
		(layer "F.Cu")
		(net "M_A_CPU1_SA_DQ<31>")
	)
	(segment
		(start 83.279488 -266.089892)
		(end 83.177888 -266.191492)
		(width 0.1016)
		(layer "F.Cu")
		(net "M_A_CPU1_SA_DQ<31>")
	)
	(segment
		(start 71.39051 -279.929336)
		(end 70.943978 -279.929336)
		(width 0.20066)
		(layer "F.Cu")
		(net "M_A_CPU1_SA_DQ<31>")
	)
	(segment
		(start 83.03768 -266.191492)
		(end 82.850736 -266.378436)
		(width 0.1016)
		(layer "F.Cu")
		(net "M_A_CPU1_SA_DQ<31>")
	)
	(segment
		(start 72.759824 -278.277066)
		(end 72.759824 -278.560022)
		(width 0.1016)
		(layer "F.Cu")
		(net "M_A_CPU1_SA_DQ<31>")
	)
	(segment
		(start 82.850736 -266.378436)
		(end 82.850736 -266.615672)
		(width 0.1016)
		(layer "F.Cu")
		(net "M_A_CPU1_SA_DQ<31>")
	)
	(segment
		(start 83.939888 -264.772902)
		(end 83.939888 -264.89025)
		(width 0.088646)
		(layer "F.Cu")
		(net "M_A_CPU1_SA_DQ<31>")
	)
	(segment
		(start 69.462142 -280.039826)
		(end 69.462142 -279.818846)
		(width 0.20066)
		(layer "F.Cu")
		(net "M_A_CPU1_SA_DQ<31>")
	)
	(segment
		(start 86.106254 -265.023854)
		(end 85.983826 -264.901426)
		(width 0.088646)
		(layer "F.Cu")
		(net "M_A_CPU1_SA_DQ<31>")
	)
	(segment
		(start 67.980306 -279.70861)
		(end 67.514978 -279.70861)
		(width 0.20066)
		(layer "F.Cu")
		(net "M_A_CPU1_SA_DQ<31>")
	)
	(segment
		(start 66.08699 -279.929336)
		(end 65.92443 -279.766776)
		(width 0.20066)
		(layer "F.Cu")
		(net "M_A_CPU1_SA_DQ<31>")
	)
	(segment
		(start 70.147942 -280.039826)
		(end 70.037706 -280.150062)
		(width 0.20066)
		(layer "F.Cu")
		(net "M_A_CPU1_SA_DQ<31>")
	)
	(segment
		(start 85.67674 -265.107928)
		(end 85.598762 -265.185906)
		(width 0.088646)
		(layer "F.Cu")
		(net "M_A_CPU1_SA_DQ<31>")
	)
	(segment
		(start 70.943978 -279.929336)
		(end 70.833742 -279.8191)
		(width 0.20066)
		(layer "F.Cu")
		(net "M_A_CPU1_SA_DQ<31>")
	)
	(segment
		(start 68.776342 -279.818846)
		(end 68.776342 -280.039826)
		(width 0.20066)
		(layer "F.Cu")
		(net "M_A_CPU1_SA_DQ<31>")
	)
	(segment
		(start 83.03768 -265.594592)
		(end 83.177888 -265.594592)
		(width 0.1016)
		(layer "F.Cu")
		(net "M_A_CPU1_SA_DQ<31>")
	)
	(segment
		(start 62.295278 -280.197306)
		(end 63.021464 -279.47112)
		(width 0.20066)
		(layer "F.Cu")
		(net "M_A_CPU1_SA_DQ<31>")
	)
	(segment
		(start 76.077064 -273.389344)
		(end 74.529442 -276.284436)
		(width 0.1016)
		(layer "F.Cu")
		(net "M_A_CPU1_SA_DQ<31>")
	)
	(segment
		(start 70.833742 -279.8191)
		(end 70.833742 -279.818846)
		(width 0.20066)
		(layer "F.Cu")
		(net "M_A_CPU1_SA_DQ<31>")
	)
	(segment
		(start 67.404742 -280.039826)
		(end 67.294506 -280.150062)
		(width 0.20066)
		(layer "F.Cu")
		(net "M_A_CPU1_SA_DQ<31>")
	)
	(segment
		(start 84.451698 -264.599928)
		(end 84.112862 -264.599928)
		(width 0.088646)
		(layer "F.Cu")
		(net "M_A_CPU1_SA_DQ<31>")
	)
	(segment
		(start 83.939888 -264.89025)
		(end 83.928204 -264.901934)
		(width 0.088646)
		(layer "F.Cu")
		(net "M_A_CPU1_SA_DQ<31>")
	)
	(segment
		(start 62.147958 -280.197306)
		(end 62.295278 -280.197306)
		(width 0.20066)
		(layer "F.Cu")
		(net "M_A_CPU1_SA_DQ<31>")
	)
	(segment
		(start 60.107068 -280.191718)
		(end 61.888116 -280.191718)
		(width 0.1016)
		(layer "F.Cu")
		(net "M_A_CPU1_SA_DQ<31>")
	)
	(segment
		(start 83.279488 -265.696192)
		(end 83.279488 -266.089892)
		(width 0.1016)
		(layer "F.Cu")
		(net "M_A_CPU1_SA_DQ<31>")
	)
	(segment
		(start 69.572378 -280.150062)
		(end 69.462142 -280.039826)
		(width 0.20066)
		(layer "F.Cu")
		(net "M_A_CPU1_SA_DQ<31>")
	)
	(segment
		(start 73.345802 -278.196548)
		(end 73.209404 -278.06015)
		(width 0.1016)
		(layer "F.Cu")
		(net "M_A_CPU1_SA_DQ<31>")
	)
	(segment
		(start 66.648584 -280.150062)
		(end 66.427858 -279.929336)
		(width 0.20066)
		(layer "F.Cu")
		(net "M_A_CPU1_SA_DQ<31>")
	)
	(segment
		(start 67.294506 -280.150062)
		(end 66.648584 -280.150062)
		(width 0.20066)
		(layer "F.Cu")
		(net "M_A_CPU1_SA_DQ<31>")
	)
	(segment
		(start 59.314842 -279.892506)
		(end 59.314842 -280.105866)
		(width 0.20066)
		(layer "F.Cu")
		(net "M_A_CPU1_SA_DQ<31>")
	)
	(segment
		(start 86.263226 -265.434826)
		(end 86.106254 -265.277854)
		(width 0.088646)
		(layer "F.Cu")
		(net "M_A_CPU1_SA_DQ<31>")
	)
	(segment
		(start 69.351906 -279.70861)
		(end 68.886578 -279.70861)
		(width 0.20066)
		(layer "F.Cu")
		(net "M_A_CPU1_SA_DQ<31>")
	)
	(segment
		(start 82.850736 -266.615672)
		(end 76.077064 -273.389344)
		(width 0.1016)
		(layer "F.Cu")
		(net "M_A_CPU1_SA_DQ<31>")
	)
	(segment
		(start 85.67674 -265.049508)
		(end 85.67674 -265.107928)
		(width 0.088646)
		(layer "F.Cu")
		(net "M_A_CPU1_SA_DQ<31>")
	)
	(segment
		(start 84.112862 -264.599928)
		(end 83.939888 -264.772902)
		(width 0.088646)
		(layer "F.Cu")
		(net "M_A_CPU1_SA_DQ<31>")
	)
	(segment
		(start 86.83244 -264.987532)
		(end 86.691724 -264.987532)
		(width 0.088646)
		(layer "F.Cu")
		(net "M_A_CPU1_SA_DQ<31>")
	)
	(segment
		(start 83.838288 -264.99185)
		(end 83.076034 -264.99185)
		(width 0.1016)
		(layer "F.Cu")
		(net "M_A_CPU1_SA_DQ<31>")
	)
	(segment
		(start 83.177888 -266.191492)
		(end 83.03768 -266.191492)
		(width 0.1016)
		(layer "F.Cu")
		(net "M_A_CPU1_SA_DQ<31>")
	)
	(segment
		(start 84.74202 -264.89025)
		(end 84.451698 -264.599928)
		(width 0.088646)
		(layer "F.Cu")
		(net "M_A_CPU1_SA_DQ<31>")
	)
	(segment
		(start 86.924388 -265.269218)
		(end 86.924388 -265.07948)
		(width 0.088646)
		(layer "F.Cu")
		(net "M_A_CPU1_SA_DQ<31>")
	)
	(segment
		(start 68.886578 -279.70861)
		(end 68.776342 -279.818846)
		(width 0.20066)
		(layer "F.Cu")
		(net "M_A_CPU1_SA_DQ<31>")
	)
	(segment
		(start 86.491826 -265.18743)
		(end 86.491826 -265.358626)
		(width 0.088646)
		(layer "F.Cu")
		(net "M_A_CPU1_SA_DQ<31>")
	)
	(segment
		(start 86.924388 -265.07948)
		(end 86.83244 -264.987532)
		(width 0.088646)
		(layer "F.Cu")
		(net "M_A_CPU1_SA_DQ<31>")
	)
	(segment
		(start 84.887054 -264.89025)
		(end 84.74202 -264.89025)
		(width 0.088646)
		(layer "F.Cu")
		(net "M_A_CPU1_SA_DQ<31>")
	)
	(segment
		(start 63.796164 -279.47112)
		(end 64.09182 -279.766776)
		(width 0.20066)
		(layer "F.Cu")
		(net "M_A_CPU1_SA_DQ<31>")
	)
	(segment
		(start 86.106254 -265.277854)
		(end 86.106254 -265.023854)
		(width 0.088646)
		(layer "F.Cu")
		(net "M_A_CPU1_SA_DQ<31>")
	)
	(segment
		(start 70.147942 -279.818846)
		(end 70.147942 -280.039826)
		(width 0.20066)
		(layer "F.Cu")
		(net "M_A_CPU1_SA_DQ<31>")
	)
	(segment
		(start 68.666106 -280.150062)
		(end 68.200778 -280.150062)
		(width 0.20066)
		(layer "F.Cu")
		(net "M_A_CPU1_SA_DQ<31>")
	)
	(segment
		(start 68.776342 -280.039826)
		(end 68.666106 -280.150062)
		(width 0.20066)
		(layer "F.Cu")
		(net "M_A_CPU1_SA_DQ<31>")
	)
	(segment
		(start 59.822842 -280.207974)
		(end 59.839098 -280.191718)
		(width 0.101854)
		(layer "F.Cu")
		(net "M_A_CPU1_SA_DQ<31>")
	)
	(segment
		(start 59.314842 -280.105866)
		(end 59.41695 -280.207974)
		(width 0.20066)
		(layer "F.Cu")
		(net "M_A_CPU1_SA_DQ<31>")
	)
	(segment
		(start 73.209404 -278.06015)
		(end 72.97674 -278.06015)
		(width 0.1016)
		(layer "F.Cu")
		(net "M_A_CPU1_SA_DQ<31>")
	)
	(segment
		(start 69.462142 -279.818846)
		(end 69.351906 -279.70861)
		(width 0.20066)
		(layer "F.Cu")
		(net "M_A_CPU1_SA_DQ<31>")
	)
	(segment
		(start 82.929222 -265.486134)
		(end 83.03768 -265.594592)
		(width 0.1016)
		(layer "F.Cu")
		(net "M_A_CPU1_SA_DQ<31>")
	)
	(segment
		(start 83.076034 -264.99185)
		(end 82.929222 -265.138662)
		(width 0.1016)
		(layer "F.Cu")
		(net "M_A_CPU1_SA_DQ<31>")
	)
	(segment
		(start 61.888116 -280.191718)
		(end 61.915548 -280.197306)
		(width 0.1016)
		(layer "F.Cu")
		(net "M_A_CPU1_SA_DQ<31>")
	)
	(segment
		(start 68.090542 -279.818846)
		(end 67.980306 -279.70861)
		(width 0.20066)
		(layer "F.Cu")
		(net "M_A_CPU1_SA_DQ<31>")
	)
	(segment
		(start 85.18271 -265.185906)
		(end 84.887054 -264.89025)
		(width 0.088646)
		(layer "F.Cu")
		(net "M_A_CPU1_SA_DQ<31>")
	)
	(segment
		(start 73.345802 -278.55291)
		(end 73.345802 -278.196548)
		(width 0.1016)
		(layer "F.Cu")
		(net "M_A_CPU1_SA_DQ<31>")
	)
	(segment
		(start 74.124312 -278.319992)
		(end 73.698608 -278.66975)
		(width 0.1016)
		(layer "F.Cu")
		(net "M_A_CPU1_SA_DQ<31>")
	)
	(segment
		(start 85.824822 -264.901426)
		(end 85.67674 -265.049508)
		(width 0.088646)
		(layer "F.Cu")
		(net "M_A_CPU1_SA_DQ<31>")
	)
	(segment
		(start 68.200778 -280.150062)
		(end 68.090542 -280.039826)
		(width 0.20066)
		(layer "F.Cu")
		(net "M_A_CPU1_SA_DQ<31>")
	)
	(segment
		(start 86.999826 -266.177014)
		(end 86.896194 -266.280646)
		(width 0.088646)
		(layer "F.Cu")
		(net "M_A_CPU1_SA_DQ<30>")
	)
	(segment
		(start 67.285108 -281.45486)
		(end 66.5099 -281.45486)
		(width 0.20066)
		(layer "F.Cu")
		(net "M_A_CPU1_SA_DQ<30>")
	)
	(segment
		(start 85.580728 -265.942318)
		(end 85.032342 -266.182348)
		(width 0.088646)
		(layer "F.Cu")
		(net "M_A_CPU1_SA_DQ<30>")
	)
	(segment
		(start 69.423788 -282.066238)
		(end 69.113908 -282.066238)
		(width 0.20066)
		(layer "F.Cu")
		(net "M_A_CPU1_SA_DQ<30>")
	)
	(segment
		(start 68.913248 -281.865578)
		(end 68.913248 -281.6606)
		(width 0.20066)
		(layer "F.Cu")
		(net "M_A_CPU1_SA_DQ<30>")
	)
	(segment
		(start 86.15807 -266.09802)
		(end 85.947504 -266.308586)
		(width 0.088646)
		(layer "F.Cu")
		(net "M_A_CPU1_SA_DQ<30>")
	)
	(segment
		(start 59.211972 -281.026362)
		(end 59.822842 -281.026362)
		(width 0.20066)
		(layer "F.Cu")
		(net "M_A_CPU1_SA_DQ<30>")
	)
	(segment
		(start 87.457534 -265.770614)
		(end 87.394796 -265.707876)
		(width 0.088646)
		(layer "F.Cu")
		(net "M_A_CPU1_SA_DQ<30>")
	)
	(segment
		(start 68.001388 -282.071572)
		(end 67.691508 -282.071572)
		(width 0.20066)
		(layer "F.Cu")
		(net "M_A_CPU1_SA_DQ<30>")
	)
	(segment
		(start 60.021978 -281.026362)
		(end 60.037218 -281.041602)
		(width 0.101854)
		(layer "F.Cu")
		(net "M_A_CPU1_SA_DQ<30>")
	)
	(segment
		(start 85.032342 -266.182348)
		(end 84.440776 -266.182348)
		(width 0.088646)
		(layer "F.Cu")
		(net "M_A_CPU1_SA_DQ<30>")
	)
	(segment
		(start 70.536308 -282.060904)
		(end 70.335648 -281.860244)
		(width 0.20066)
		(layer "F.Cu")
		(net "M_A_CPU1_SA_DQ<30>")
	)
	(segment
		(start 71.046848 -281.6606)
		(end 71.046848 -281.860244)
		(width 0.20066)
		(layer "F.Cu")
		(net "M_A_CPU1_SA_DQ<30>")
	)
	(segment
		(start 76.57211 -273.757898)
		(end 75.110086 -276.49297)
		(width 0.1016)
		(layer "F.Cu")
		(net "M_A_CPU1_SA_DQ<30>")
	)
	(segment
		(start 87.24392 -265.707876)
		(end 86.999826 -265.95197)
		(width 0.088646)
		(layer "F.Cu")
		(net "M_A_CPU1_SA_DQ<30>")
	)
	(segment
		(start 83.901788 -266.07008)
		(end 83.901788 -266.42822)
		(width 0.1016)
		(layer "F.Cu")
		(net "M_A_CPU1_SA_DQ<30>")
	)
	(segment
		(start 86.896194 -266.280646)
		(end 86.764622 -266.280646)
		(width 0.088646)
		(layer "F.Cu")
		(net "M_A_CPU1_SA_DQ<30>")
	)
	(segment
		(start 67.490848 -281.870912)
		(end 67.490848 -281.6606)
		(width 0.20066)
		(layer "F.Cu")
		(net "M_A_CPU1_SA_DQ<30>")
	)
	(segment
		(start 59.102752 -281.324558)
		(end 59.102752 -281.135582)
		(width 0.20066)
		(layer "F.Cu")
		(net "M_A_CPU1_SA_DQ<30>")
	)
	(segment
		(start 73.674478 -279.459944)
		(end 73.380346 -279.754076)
		(width 0.1016)
		(layer "F.Cu")
		(net "M_A_CPU1_SA_DQ<30>")
	)
	(segment
		(start 87.394796 -265.707876)
		(end 87.24392 -265.707876)
		(width 0.088646)
		(layer "F.Cu")
		(net "M_A_CPU1_SA_DQ<30>")
	)
	(segment
		(start 58.960512 -281.466798)
		(end 59.102752 -281.324558)
		(width 0.20066)
		(layer "F.Cu")
		(net "M_A_CPU1_SA_DQ<30>")
	)
	(segment
		(start 57.503314 -281.466798)
		(end 58.960512 -281.466798)
		(width 0.20066)
		(layer "F.Cu")
		(net "M_A_CPU1_SA_DQ<30>")
	)
	(segment
		(start 62.51702 -281.182572)
		(end 62.51702 -281.422094)
		(width 0.20066)
		(layer "F.Cu")
		(net "M_A_CPU1_SA_DQ<30>")
	)
	(segment
		(start 86.669626 -266.18565)
		(end 86.669626 -265.951208)
		(width 0.088646)
		(layer "F.Cu")
		(net "M_A_CPU1_SA_DQ<30>")
	)
	(segment
		(start 70.134988 -281.45994)
		(end 69.825108 -281.45994)
		(width 0.20066)
		(layer "F.Cu")
		(net "M_A_CPU1_SA_DQ<30>")
	)
	(segment
		(start 62.951614 -281.595068)
		(end 63.079884 -281.466798)
		(width 0.20066)
		(layer "F.Cu")
		(net "M_A_CPU1_SA_DQ<30>")
	)
	(segment
		(start 60.037218 -281.041602)
		(end 61.863986 -281.041602)
		(width 0.1016)
		(layer "F.Cu")
		(net "M_A_CPU1_SA_DQ<30>")
	)
	(segment
		(start 73.380346 -279.754076)
		(end 71.674482 -281.45994)
		(width 0.20066)
		(layer "F.Cu")
		(net "M_A_CPU1_SA_DQ<30>")
	)
	(segment
		(start 86.669626 -265.951208)
		(end 86.425278 -265.70686)
		(width 0.088646)
		(layer "F.Cu")
		(net "M_A_CPU1_SA_DQ<30>")
	)
	(segment
		(start 68.202048 -281.6606)
		(end 68.202048 -281.870912)
		(width 0.20066)
		(layer "F.Cu")
		(net "M_A_CPU1_SA_DQ<30>")
	)
	(segment
		(start 84.126832 -265.997436)
		(end 83.974432 -265.997436)
		(width 0.1016)
		(layer "F.Cu")
		(net "M_A_CPU1_SA_DQ<30>")
	)
	(segment
		(start 71.247508 -281.45994)
		(end 71.046848 -281.6606)
		(width 0.20066)
		(layer "F.Cu")
		(net "M_A_CPU1_SA_DQ<30>")
	)
	(segment
		(start 86.764622 -266.280646)
		(end 86.669626 -266.18565)
		(width 0.088646)
		(layer "F.Cu")
		(net "M_A_CPU1_SA_DQ<30>")
	)
	(segment
		(start 87.315294 -266.080748)
		(end 87.457534 -265.938508)
		(width 0.088646)
		(layer "F.Cu")
		(net "M_A_CPU1_SA_DQ<30>")
	)
	(segment
		(start 68.712588 -281.45994)
		(end 68.402708 -281.45994)
		(width 0.20066)
		(layer "F.Cu")
		(net "M_A_CPU1_SA_DQ<30>")
	)
	(segment
		(start 63.079884 -281.466798)
		(end 65.047114 -281.466798)
		(width 0.20066)
		(layer "F.Cu")
		(net "M_A_CPU1_SA_DQ<30>")
	)
	(segment
		(start 75.110086 -276.49297)
		(end 74.635614 -278.879808)
		(width 0.1016)
		(layer "F.Cu")
		(net "M_A_CPU1_SA_DQ<30>")
	)
	(segment
		(start 69.113908 -282.066238)
		(end 68.913248 -281.865578)
		(width 0.20066)
		(layer "F.Cu")
		(net "M_A_CPU1_SA_DQ<30>")
	)
	(segment
		(start 59.822842 -281.026362)
		(end 60.021978 -281.026362)
		(width 0.101854)
		(layer "F.Cu")
		(net "M_A_CPU1_SA_DQ<30>")
	)
	(segment
		(start 74.635614 -278.879808)
		(end 74.055478 -279.459944)
		(width 0.1016)
		(layer "F.Cu")
		(net "M_A_CPU1_SA_DQ<30>")
	)
	(segment
		(start 61.863986 -281.041602)
		(end 61.865002 -281.040586)
		(width 0.1016)
		(layer "F.Cu")
		(net "M_A_CPU1_SA_DQ<30>")
	)
	(segment
		(start 70.335648 -281.860244)
		(end 70.335648 -281.6606)
		(width 0.20066)
		(layer "F.Cu")
		(net "M_A_CPU1_SA_DQ<30>")
	)
	(segment
		(start 62.147958 -281.040586)
		(end 62.375034 -281.040586)
		(width 0.20066)
		(layer "F.Cu")
		(net "M_A_CPU1_SA_DQ<30>")
	)
	(segment
		(start 69.624448 -281.865578)
		(end 69.423788 -282.066238)
		(width 0.20066)
		(layer "F.Cu")
		(net "M_A_CPU1_SA_DQ<30>")
	)
	(segment
		(start 85.947504 -266.308586)
		(end 85.851492 -266.308586)
		(width 0.088646)
		(layer "F.Cu")
		(net "M_A_CPU1_SA_DQ<30>")
	)
	(segment
		(start 68.913248 -281.6606)
		(end 68.712588 -281.45994)
		(width 0.20066)
		(layer "F.Cu")
		(net "M_A_CPU1_SA_DQ<30>")
	)
	(segment
		(start 66.497962 -281.466798)
		(end 65.047114 -281.466798)
		(width 0.20066)
		(layer "F.Cu")
		(net "M_A_CPU1_SA_DQ<30>")
	)
	(segment
		(start 86.425278 -265.70686)
		(end 86.312756 -265.70686)
		(width 0.088646)
		(layer "F.Cu")
		(net "M_A_CPU1_SA_DQ<30>")
	)
	(segment
		(start 61.865002 -281.040586)
		(end 62.147958 -281.040586)
		(width 0.101854)
		(layer "F.Cu")
		(net "M_A_CPU1_SA_DQ<30>")
	)
	(segment
		(start 86.999826 -265.95197)
		(end 86.999826 -266.177014)
		(width 0.088646)
		(layer "F.Cu")
		(net "M_A_CPU1_SA_DQ<30>")
	)
	(segment
		(start 71.674482 -281.45994)
		(end 71.247508 -281.45994)
		(width 0.20066)
		(layer "F.Cu")
		(net "M_A_CPU1_SA_DQ<30>")
	)
	(segment
		(start 70.335648 -281.6606)
		(end 70.134988 -281.45994)
		(width 0.20066)
		(layer "F.Cu")
		(net "M_A_CPU1_SA_DQ<30>")
	)
	(segment
		(start 87.457534 -265.938508)
		(end 87.457534 -265.770614)
		(width 0.088646)
		(layer "F.Cu")
		(net "M_A_CPU1_SA_DQ<30>")
	)
	(segment
		(start 69.624448 -281.6606)
		(end 69.624448 -281.865578)
		(width 0.20066)
		(layer "F.Cu")
		(net "M_A_CPU1_SA_DQ<30>")
	)
	(segment
		(start 66.5099 -281.45486)
		(end 66.497962 -281.466798)
		(width 0.20066)
		(layer "F.Cu")
		(net "M_A_CPU1_SA_DQ<30>")
	)
	(segment
		(start 83.974432 -265.997436)
		(end 83.901788 -266.07008)
		(width 0.1016)
		(layer "F.Cu")
		(net "M_A_CPU1_SA_DQ<30>")
	)
	(segment
		(start 67.691508 -282.071572)
		(end 67.490848 -281.870912)
		(width 0.20066)
		(layer "F.Cu")
		(net "M_A_CPU1_SA_DQ<30>")
	)
	(segment
		(start 62.689994 -281.595068)
		(end 62.951614 -281.595068)
		(width 0.20066)
		(layer "F.Cu")
		(net "M_A_CPU1_SA_DQ<30>")
	)
	(segment
		(start 85.696552 -265.942318)
		(end 85.580728 -265.942318)
		(width 0.088646)
		(layer "F.Cu")
		(net "M_A_CPU1_SA_DQ<30>")
	)
	(segment
		(start 62.375034 -281.040586)
		(end 62.51702 -281.182572)
		(width 0.20066)
		(layer "F.Cu")
		(net "M_A_CPU1_SA_DQ<30>")
	)
	(segment
		(start 71.046848 -281.860244)
		(end 70.846188 -282.060904)
		(width 0.20066)
		(layer "F.Cu")
		(net "M_A_CPU1_SA_DQ<30>")
	)
	(segment
		(start 68.402708 -281.45994)
		(end 68.202048 -281.6606)
		(width 0.20066)
		(layer "F.Cu")
		(net "M_A_CPU1_SA_DQ<30>")
	)
	(segment
		(start 59.102752 -281.135582)
		(end 59.211972 -281.026362)
		(width 0.20066)
		(layer "F.Cu")
		(net "M_A_CPU1_SA_DQ<30>")
	)
	(segment
		(start 68.202048 -281.870912)
		(end 68.001388 -282.071572)
		(width 0.20066)
		(layer "F.Cu")
		(net "M_A_CPU1_SA_DQ<30>")
	)
	(segment
		(start 69.825108 -281.45994)
		(end 69.624448 -281.6606)
		(width 0.20066)
		(layer "F.Cu")
		(net "M_A_CPU1_SA_DQ<30>")
	)
	(segment
		(start 74.055478 -279.459944)
		(end 73.674478 -279.459944)
		(width 0.1016)
		(layer "F.Cu")
		(net "M_A_CPU1_SA_DQ<30>")
	)
	(segment
		(start 85.743796 -266.20089)
		(end 85.743796 -265.989562)
		(width 0.088646)
		(layer "F.Cu")
		(net "M_A_CPU1_SA_DQ<30>")
	)
	(segment
		(start 85.851492 -266.308586)
		(end 85.743796 -266.20089)
		(width 0.088646)
		(layer "F.Cu")
		(net "M_A_CPU1_SA_DQ<30>")
	)
	(segment
		(start 85.743796 -265.989562)
		(end 85.696552 -265.942318)
		(width 0.088646)
		(layer "F.Cu")
		(net "M_A_CPU1_SA_DQ<30>")
	)
	(segment
		(start 87.315294 -266.405868)
		(end 87.315294 -266.080748)
		(width 0.088646)
		(layer "F.Cu")
		(net "M_A_CPU1_SA_DQ<30>")
	)
	(segment
		(start 86.312756 -265.70686)
		(end 86.15807 -265.861546)
		(width 0.088646)
		(layer "F.Cu")
		(net "M_A_CPU1_SA_DQ<30>")
	)
	(segment
		(start 84.440776 -266.182348)
		(end 84.255864 -265.997436)
		(width 0.088646)
		(layer "F.Cu")
		(net "M_A_CPU1_SA_DQ<30>")
	)
	(segment
		(start 70.846188 -282.060904)
		(end 70.536308 -282.060904)
		(width 0.20066)
		(layer "F.Cu")
		(net "M_A_CPU1_SA_DQ<30>")
	)
	(segment
		(start 62.51702 -281.422094)
		(end 62.689994 -281.595068)
		(width 0.20066)
		(layer "F.Cu")
		(net "M_A_CPU1_SA_DQ<30>")
	)
	(segment
		(start 83.901788 -266.42822)
		(end 76.57211 -273.757898)
		(width 0.1016)
		(layer "F.Cu")
		(net "M_A_CPU1_SA_DQ<30>")
	)
	(segment
		(start 86.15807 -265.861546)
		(end 86.15807 -266.09802)
		(width 0.088646)
		(layer "F.Cu")
		(net "M_A_CPU1_SA_DQ<30>")
	)
	(segment
		(start 67.490848 -281.6606)
		(end 67.285108 -281.45486)
		(width 0.20066)
		(layer "F.Cu")
		(net "M_A_CPU1_SA_DQ<30>")
	)
	(segment
		(start 84.255864 -265.997436)
		(end 84.126832 -265.997436)
		(width 0.088646)
		(layer "F.Cu")
		(net "M_A_CPU1_SA_DQ<30>")
	)
	(segment
		(start 87.977472 -278.93772)
		(end 87.878412 -278.978868)
		(width 0.088646)
		(layer "F.Cu")
		(net "M_A_CPU1_SA_DQ<2>")
	)
	(segment
		(start 64.724534 -315.46673)
		(end 64.72428 -315.466984)
		(width 0.20066)
		(layer "F.Cu")
		(net "M_A_CPU1_SA_DQ<2>")
	)
	(segment
		(start 88.394032 -278.406098)
		(end 88.063578 -278.851614)
		(width 0.088646)
		(layer "F.Cu")
		(net "M_A_CPU1_SA_DQ<2>")
	)
	(segment
		(start 85.530182 -279.948132)
		(end 85.332824 -280.21407)
		(width 0.1016)
		(layer "F.Cu")
		(net "M_A_CPU1_SA_DQ<2>")
	)
	(segment
		(start 64.72428 -315.466984)
		(end 63.329058 -315.466984)
		(width 0.20066)
		(layer "F.Cu")
		(net "M_A_CPU1_SA_DQ<2>")
	)
	(segment
		(start 59.862212 -315.041534)
		(end 59.821826 -315.041534)
		(width 0.101854)
		(layer "F.Cu")
		(net "M_A_CPU1_SA_DQ<2>")
	)
	(segment
		(start 88.623648 -278.24303)
		(end 88.476582 -278.314912)
		(width 0.088646)
		(layer "F.Cu")
		(net "M_A_CPU1_SA_DQ<2>")
	)
	(segment
		(start 59.809126 -315.028834)
		(end 59.806586 -315.028834)
		(width 0.101854)
		(layer "F.Cu")
		(net "M_A_CPU1_SA_DQ<2>")
	)
	(segment
		(start 63.329058 -315.466984)
		(end 63.115444 -315.680598)
		(width 0.20066)
		(layer "F.Cu")
		(net "M_A_CPU1_SA_DQ<2>")
	)
	(segment
		(start 85.888576 -279.455626)
		(end 85.868256 -279.482042)
		(width 0.088646)
		(layer "F.Cu")
		(net "M_A_CPU1_SA_DQ<2>")
	)
	(segment
		(start 59.806586 -315.028834)
		(end 59.253374 -315.028834)
		(width 0.20066)
		(layer "F.Cu")
		(net "M_A_CPU1_SA_DQ<2>")
	)
	(segment
		(start 70.23735 -313.569096)
		(end 68.93052 -314.442348)
		(width 0.20066)
		(layer "F.Cu")
		(net "M_A_CPU1_SA_DQ<2>")
	)
	(segment
		(start 62.131702 -315.042296)
		(end 62.072774 -315.042296)
		(width 0.101854)
		(layer "F.Cu")
		(net "M_A_CPU1_SA_DQ<2>")
	)
	(segment
		(start 89.218262 -278.16937)
		(end 88.623648 -278.24303)
		(width 0.088646)
		(layer "F.Cu")
		(net "M_A_CPU1_SA_DQ<2>")
	)
	(segment
		(start 68.93052 -314.442348)
		(end 66.977514 -315.251592)
		(width 0.20066)
		(layer "F.Cu")
		(net "M_A_CPU1_SA_DQ<2>")
	)
	(segment
		(start 85.971888 -279.331928)
		(end 85.888576 -279.455626)
		(width 0.088646)
		(layer "F.Cu")
		(net "M_A_CPU1_SA_DQ<2>")
	)
	(segment
		(start 62.51702 -315.194442)
		(end 62.364874 -315.042296)
		(width 0.20066)
		(layer "F.Cu")
		(net "M_A_CPU1_SA_DQ<2>")
	)
	(segment
		(start 65.047114 -315.46673)
		(end 64.724534 -315.46673)
		(width 0.20066)
		(layer "F.Cu")
		(net "M_A_CPU1_SA_DQ<2>")
	)
	(segment
		(start 85.332824 -280.21407)
		(end 84.86648 -281.08529)
		(width 0.1016)
		(layer "F.Cu")
		(net "M_A_CPU1_SA_DQ<2>")
	)
	(segment
		(start 58.815478 -315.46673)
		(end 57.503314 -315.46673)
		(width 0.20066)
		(layer "F.Cu")
		(net "M_A_CPU1_SA_DQ<2>")
	)
	(segment
		(start 66.458084 -315.46673)
		(end 65.047114 -315.46673)
		(width 0.20066)
		(layer "F.Cu")
		(net "M_A_CPU1_SA_DQ<2>")
	)
	(segment
		(start 62.698376 -315.680598)
		(end 62.51702 -315.499242)
		(width 0.20066)
		(layer "F.Cu")
		(net "M_A_CPU1_SA_DQ<2>")
	)
	(segment
		(start 62.51702 -315.499242)
		(end 62.51702 -315.194442)
		(width 0.20066)
		(layer "F.Cu")
		(net "M_A_CPU1_SA_DQ<2>")
	)
	(segment
		(start 62.364874 -315.042296)
		(end 62.131702 -315.042296)
		(width 0.20066)
		(layer "F.Cu")
		(net "M_A_CPU1_SA_DQ<2>")
	)
	(segment
		(start 59.821826 -315.041534)
		(end 59.809126 -315.028834)
		(width 0.101854)
		(layer "F.Cu")
		(net "M_A_CPU1_SA_DQ<2>")
	)
	(segment
		(start 84.538312 -297.266868)
		(end 84.393024 -298.244514)
		(width 0.1016)
		(layer "F.Cu")
		(net "M_A_CPU1_SA_DQ<2>")
	)
	(segment
		(start 84.04225 -299.764196)
		(end 70.23735 -313.569096)
		(width 0.20066)
		(layer "F.Cu")
		(net "M_A_CPU1_SA_DQ<2>")
	)
	(segment
		(start 59.253374 -315.028834)
		(end 58.815478 -315.46673)
		(width 0.20066)
		(layer "F.Cu")
		(net "M_A_CPU1_SA_DQ<2>")
	)
	(segment
		(start 90.134694 -277.800562)
		(end 89.48547 -278.105108)
		(width 0.088646)
		(layer "F.Cu")
		(net "M_A_CPU1_SA_DQ<2>")
	)
	(segment
		(start 89.48547 -278.105108)
		(end 89.218262 -278.16937)
		(width 0.088646)
		(layer "F.Cu")
		(net "M_A_CPU1_SA_DQ<2>")
	)
	(segment
		(start 66.977514 -315.251592)
		(end 66.458084 -315.46673)
		(width 0.20066)
		(layer "F.Cu")
		(net "M_A_CPU1_SA_DQ<2>")
	)
	(segment
		(start 88.476582 -278.314912)
		(end 88.394032 -278.406098)
		(width 0.088646)
		(layer "F.Cu")
		(net "M_A_CPU1_SA_DQ<2>")
	)
	(segment
		(start 84.86648 -281.08529)
		(end 84.778596 -281.329892)
		(width 0.1016)
		(layer "F.Cu")
		(net "M_A_CPU1_SA_DQ<2>")
	)
	(segment
		(start 84.393024 -298.244514)
		(end 84.118958 -299.619924)
		(width 0.1016)
		(layer "F.Cu")
		(net "M_A_CPU1_SA_DQ<2>")
	)
	(segment
		(start 84.778596 -281.329892)
		(end 84.538312 -282.529026)
		(width 0.1016)
		(layer "F.Cu")
		(net "M_A_CPU1_SA_DQ<2>")
	)
	(segment
		(start 85.86978 -279.49271)
		(end 85.530182 -279.948132)
		(width 0.088646)
		(layer "F.Cu")
		(net "M_A_CPU1_SA_DQ<2>")
	)
	(segment
		(start 85.868256 -279.482042)
		(end 85.86978 -279.49271)
		(width 0.088646)
		(layer "F.Cu")
		(net "M_A_CPU1_SA_DQ<2>")
	)
	(segment
		(start 84.118958 -299.619924)
		(end 84.118958 -299.687488)
		(width 0.1016)
		(layer "F.Cu")
		(net "M_A_CPU1_SA_DQ<2>")
	)
	(segment
		(start 84.118958 -299.687488)
		(end 84.04225 -299.764196)
		(width 0.1016)
		(layer "F.Cu")
		(net "M_A_CPU1_SA_DQ<2>")
	)
	(segment
		(start 62.072774 -315.042296)
		(end 62.072012 -315.041534)
		(width 0.101854)
		(layer "F.Cu")
		(net "M_A_CPU1_SA_DQ<2>")
	)
	(segment
		(start 84.538312 -282.529026)
		(end 84.538312 -297.266868)
		(width 0.1016)
		(layer "F.Cu")
		(net "M_A_CPU1_SA_DQ<2>")
	)
	(segment
		(start 87.128096 -279.103836)
		(end 87.113364 -279.112472)
		(width 0.088646)
		(layer "F.Cu")
		(net "M_A_CPU1_SA_DQ<2>")
	)
	(segment
		(start 63.115444 -315.680598)
		(end 62.698376 -315.680598)
		(width 0.20066)
		(layer "F.Cu")
		(net "M_A_CPU1_SA_DQ<2>")
	)
	(segment
		(start 88.063578 -278.851614)
		(end 87.977472 -278.93772)
		(width 0.088646)
		(layer "F.Cu")
		(net "M_A_CPU1_SA_DQ<2>")
	)
	(segment
		(start 62.072012 -315.041534)
		(end 59.862212 -315.041534)
		(width 0.1016)
		(layer "F.Cu")
		(net "M_A_CPU1_SA_DQ<2>")
	)
	(segment
		(start 86.188296 -279.103836)
		(end 86.109556 -279.149302)
		(width 0.088646)
		(layer "F.Cu")
		(net "M_A_CPU1_SA_DQ<2>")
	)
	(segment
		(start 87.878412 -278.978868)
		(end 87.58809 -278.978868)
		(width 0.088646)
		(layer "F.Cu")
		(net "M_A_CPU1_SA_DQ<2>")
	)
	(arc
		(start 86.109556 -279.149302)
		(mid 86.053571 -279.193961)
		(end 86.01329 -279.253188)
		(width 0.088646)
		(layer "F.Cu")
		(net "M_A_CPU1_SA_DQ<2>")
	)
	(arc
		(start 87.58809 -278.978868)
		(mid 87.349761 -279.010674)
		(end 87.128096 -279.103836)
		(width 0.088646)
		(layer "F.Cu")
		(net "M_A_CPU1_SA_DQ<2>")
	)
	(arc
		(start 86.562692 -279.103836)
		(mid 86.375494 -279.053693)
		(end 86.188296 -279.103836)
		(width 0.088646)
		(layer "F.Cu")
		(net "M_A_CPU1_SA_DQ<2>")
	)
	(arc
		(start 87.113364 -279.112472)
		(mid 86.836889 -279.179792)
		(end 86.562692 -279.103836)
		(width 0.088646)
		(layer "F.Cu")
		(net "M_A_CPU1_SA_DQ<2>")
	)
	(arc
		(start 86.01329 -279.253188)
		(mid 85.99339 -279.292979)
		(end 85.971888 -279.331928)
		(width 0.088646)
		(layer "F.Cu")
		(net "M_A_CPU1_SA_DQ<2>")
	)
	(segment
		(start 83.902804 -265.550396)
		(end 83.711288 -265.550396)
		(width 0.1016)
		(layer "F.Cu")
		(net "M_A_CPU1_SA_DQ<29>")
	)
	(segment
		(start 85.303106 -265.83005)
		(end 85.153246 -265.91641)
		(width 0.088646)
		(layer "F.Cu")
		(net "M_A_CPU1_SA_DQ<29>")
	)
	(segment
		(start 63.630048 -281.062176)
		(end 63.45555 -280.887678)
		(width 0.20066)
		(layer "F.Cu")
		(net "M_A_CPU1_SA_DQ<29>")
	)
	(segment
		(start 53.403246 -280.61666)
		(end 54.201822 -280.61666)
		(width 0.20066)
		(layer "F.Cu")
		(net "M_A_CPU1_SA_DQ<29>")
	)
	(segment
		(start 54.416706 -280.831544)
		(end 54.865778 -280.831544)
		(width 0.20066)
		(layer "F.Cu")
		(net "M_A_CPU1_SA_DQ<29>")
	)
	(segment
		(start 73.106026 -279.122124)
		(end 72.92721 -279.30094)
		(width 0.1016)
		(layer "F.Cu")
		(net "M_A_CPU1_SA_DQ<29>")
	)
	(segment
		(start 83.711288 -265.550396)
		(end 83.59013 -265.671554)
		(width 0.1016)
		(layer "F.Cu")
		(net "M_A_CPU1_SA_DQ<29>")
	)
	(segment
		(start 85.905594 -265.592306)
		(end 85.68944 -265.376152)
		(width 0.088646)
		(layer "F.Cu")
		(net "M_A_CPU1_SA_DQ<29>")
	)
	(segment
		(start 65.903348 -281.041602)
		(end 64.185292 -281.041602)
		(width 0.1016)
		(layer "F.Cu")
		(net "M_A_CPU1_SA_DQ<29>")
	)
	(segment
		(start 58.704226 -280.191718)
		(end 58.81116 -280.191718)
		(width 0.20066)
		(layer "F.Cu")
		(net "M_A_CPU1_SA_DQ<29>")
	)
	(segment
		(start 54.865778 -280.831544)
		(end 55.033164 -280.664158)
		(width 0.20066)
		(layer "F.Cu")
		(net "M_A_CPU1_SA_DQ<29>")
	)
	(segment
		(start 58.668412 -280.191718)
		(end 58.704226 -280.191718)
		(width 0.101854)
		(layer "F.Cu")
		(net "M_A_CPU1_SA_DQ<29>")
	)
	(segment
		(start 66.61531 -280.815288)
		(end 66.377566 -281.053032)
		(width 0.20066)
		(layer "F.Cu")
		(net "M_A_CPU1_SA_DQ<29>")
	)
	(segment
		(start 66.212212 -281.053032)
		(end 65.930526 -281.053032)
		(width 0.101854)
		(layer "F.Cu")
		(net "M_A_CPU1_SA_DQ<29>")
	)
	(segment
		(start 55.033164 -280.334974)
		(end 55.19547 -280.172668)
		(width 0.20066)
		(layer "F.Cu")
		(net "M_A_CPU1_SA_DQ<29>")
	)
	(segment
		(start 63.45555 -280.179272)
		(end 63.339218 -280.06294)
		(width 0.20066)
		(layer "F.Cu")
		(net "M_A_CPU1_SA_DQ<29>")
	)
	(segment
		(start 63.084202 -280.06294)
		(end 62.530482 -280.61666)
		(width 0.20066)
		(layer "F.Cu")
		(net "M_A_CPU1_SA_DQ<29>")
	)
	(segment
		(start 63.977012 -281.062176)
		(end 63.630048 -281.062176)
		(width 0.20066)
		(layer "F.Cu")
		(net "M_A_CPU1_SA_DQ<29>")
	)
	(segment
		(start 59.236102 -280.61666)
		(end 60.947046 -280.61666)
		(width 0.20066)
		(layer "F.Cu")
		(net "M_A_CPU1_SA_DQ<29>")
	)
	(segment
		(start 63.45555 -280.887678)
		(end 63.45555 -280.179272)
		(width 0.20066)
		(layer "F.Cu")
		(net "M_A_CPU1_SA_DQ<29>")
	)
	(segment
		(start 83.59013 -265.671554)
		(end 83.59013 -266.307824)
		(width 0.1016)
		(layer "F.Cu")
		(net "M_A_CPU1_SA_DQ<29>")
	)
	(segment
		(start 55.19547 -280.172668)
		(end 56.37911 -280.172668)
		(width 0.20066)
		(layer "F.Cu")
		(net "M_A_CPU1_SA_DQ<29>")
	)
	(segment
		(start 83.59013 -266.307824)
		(end 76.324714 -273.57324)
		(width 0.1016)
		(layer "F.Cu")
		(net "M_A_CPU1_SA_DQ<29>")
	)
	(segment
		(start 85.303106 -265.4808)
		(end 85.303106 -265.83005)
		(width 0.088646)
		(layer "F.Cu")
		(net "M_A_CPU1_SA_DQ<29>")
	)
	(segment
		(start 72.92721 -279.30094)
		(end 71.412862 -280.815288)
		(width 0.20066)
		(layer "F.Cu")
		(net "M_A_CPU1_SA_DQ<29>")
	)
	(segment
		(start 76.324714 -273.57324)
		(end 74.819764 -276.38883)
		(width 0.1016)
		(layer "F.Cu")
		(net "M_A_CPU1_SA_DQ<29>")
	)
	(segment
		(start 84.237322 -265.59383)
		(end 84.132674 -265.550396)
		(width 0.088646)
		(layer "F.Cu")
		(net "M_A_CPU1_SA_DQ<29>")
	)
	(segment
		(start 84.132674 -265.550396)
		(end 83.902804 -265.550396)
		(width 0.088646)
		(layer "F.Cu")
		(net "M_A_CPU1_SA_DQ<29>")
	)
	(segment
		(start 56.39816 -280.191718)
		(end 58.668412 -280.191718)
		(width 0.1016)
		(layer "F.Cu")
		(net "M_A_CPU1_SA_DQ<29>")
	)
	(segment
		(start 64.185292 -281.041602)
		(end 64.12611 -281.062176)
		(width 0.1016)
		(layer "F.Cu")
		(net "M_A_CPU1_SA_DQ<29>")
	)
	(segment
		(start 73.852278 -279.122124)
		(end 73.106026 -279.122124)
		(width 0.1016)
		(layer "F.Cu")
		(net "M_A_CPU1_SA_DQ<29>")
	)
	(segment
		(start 66.377566 -281.053032)
		(end 66.212212 -281.053032)
		(width 0.20066)
		(layer "F.Cu")
		(net "M_A_CPU1_SA_DQ<29>")
	)
	(segment
		(start 85.68944 -265.376152)
		(end 85.407754 -265.376152)
		(width 0.088646)
		(layer "F.Cu")
		(net "M_A_CPU1_SA_DQ<29>")
	)
	(segment
		(start 71.412862 -280.815288)
		(end 66.61531 -280.815288)
		(width 0.20066)
		(layer "F.Cu")
		(net "M_A_CPU1_SA_DQ<29>")
	)
	(segment
		(start 85.407754 -265.376152)
		(end 85.303106 -265.4808)
		(width 0.088646)
		(layer "F.Cu")
		(net "M_A_CPU1_SA_DQ<29>")
	)
	(segment
		(start 54.201822 -280.61666)
		(end 54.416706 -280.831544)
		(width 0.20066)
		(layer "F.Cu")
		(net "M_A_CPU1_SA_DQ<29>")
	)
	(segment
		(start 56.37911 -280.172668)
		(end 56.39816 -280.191718)
		(width 0.101854)
		(layer "F.Cu")
		(net "M_A_CPU1_SA_DQ<29>")
	)
	(segment
		(start 62.530482 -280.61666)
		(end 60.947046 -280.61666)
		(width 0.20066)
		(layer "F.Cu")
		(net "M_A_CPU1_SA_DQ<29>")
	)
	(segment
		(start 64.12611 -281.062176)
		(end 63.977012 -281.062176)
		(width 0.101854)
		(layer "F.Cu")
		(net "M_A_CPU1_SA_DQ<29>")
	)
	(segment
		(start 74.819764 -276.38883)
		(end 74.381106 -278.593296)
		(width 0.1016)
		(layer "F.Cu")
		(net "M_A_CPU1_SA_DQ<29>")
	)
	(segment
		(start 84.959698 -265.969496)
		(end 84.612988 -265.969496)
		(width 0.088646)
		(layer "F.Cu")
		(net "M_A_CPU1_SA_DQ<29>")
	)
	(segment
		(start 65.930526 -281.053032)
		(end 65.903348 -281.041602)
		(width 0.1016)
		(layer "F.Cu")
		(net "M_A_CPU1_SA_DQ<29>")
	)
	(segment
		(start 84.612988 -265.969496)
		(end 84.237322 -265.59383)
		(width 0.088646)
		(layer "F.Cu")
		(net "M_A_CPU1_SA_DQ<29>")
	)
	(segment
		(start 58.81116 -280.191718)
		(end 59.236102 -280.61666)
		(width 0.20066)
		(layer "F.Cu")
		(net "M_A_CPU1_SA_DQ<29>")
	)
	(segment
		(start 74.381106 -278.593296)
		(end 73.852278 -279.122124)
		(width 0.1016)
		(layer "F.Cu")
		(net "M_A_CPU1_SA_DQ<29>")
	)
	(segment
		(start 63.339218 -280.06294)
		(end 63.084202 -280.06294)
		(width 0.20066)
		(layer "F.Cu")
		(net "M_A_CPU1_SA_DQ<29>")
	)
	(segment
		(start 55.033164 -280.664158)
		(end 55.033164 -280.334974)
		(width 0.20066)
		(layer "F.Cu")
		(net "M_A_CPU1_SA_DQ<29>")
	)
	(arc
		(start 85.153246 -265.91641)
		(mid 85.059876 -265.955368)
		(end 84.959698 -265.969496)
		(width 0.088646)
		(layer "F.Cu")
		(net "M_A_CPU1_SA_DQ<29>")
	)
	(segment
		(start 62.532006 -282.302458)
		(end 62.865 -282.495498)
		(width 0.20066)
		(layer "F.Cu")
		(net "M_A_CPU1_SA_DQ<28>")
	)
	(segment
		(start 54.958234 -281.9781)
		(end 55.06212 -281.874214)
		(width 0.20066)
		(layer "F.Cu")
		(net "M_A_CPU1_SA_DQ<28>")
	)
	(segment
		(start 66.620136 -281.95397)
		(end 66.729864 -282.063698)
		(width 0.20066)
		(layer "F.Cu")
		(net "M_A_CPU1_SA_DQ<28>")
	)
	(segment
		(start 56.38419 -281.874214)
		(end 56.401716 -281.89174)
		(width 0.101854)
		(layer "F.Cu")
		(net "M_A_CPU1_SA_DQ<28>")
	)
	(segment
		(start 66.729864 -282.063698)
		(end 66.745104 -282.100782)
		(width 0.20066)
		(layer "F.Cu")
		(net "M_A_CPU1_SA_DQ<28>")
	)
	(segment
		(start 75.400408 -276.597364)
		(end 76.821538 -273.939762)
		(width 0.1016)
		(layer "F.Cu")
		(net "M_A_CPU1_SA_DQ<28>")
	)
	(segment
		(start 76.821538 -273.939762)
		(end 83.391248 -267.370052)
		(width 0.1016)
		(layer "F.Cu")
		(net "M_A_CPU1_SA_DQ<28>")
	)
	(segment
		(start 68.702428 -282.585414)
		(end 68.982844 -282.86583)
		(width 0.20066)
		(layer "F.Cu")
		(net "M_A_CPU1_SA_DQ<28>")
	)
	(segment
		(start 60.947046 -282.316682)
		(end 61.44514 -282.316682)
		(width 0.20066)
		(layer "F.Cu")
		(net "M_A_CPU1_SA_DQ<28>")
	)
	(segment
		(start 66.446654 -281.882088)
		(end 66.620136 -281.95397)
		(width 0.20066)
		(layer "F.Cu")
		(net "M_A_CPU1_SA_DQ<28>")
	)
	(segment
		(start 53.403246 -282.316682)
		(end 54.248558 -282.316682)
		(width 0.20066)
		(layer "F.Cu")
		(net "M_A_CPU1_SA_DQ<28>")
	)
	(segment
		(start 74.417174 -280.253694)
		(end 74.594212 -280.076656)
		(width 0.1016)
		(layer "F.Cu")
		(net "M_A_CPU1_SA_DQ<28>")
	)
	(segment
		(start 84.069682 -266.787376)
		(end 84.069682 -266.697206)
		(width 0.088646)
		(layer "F.Cu")
		(net "M_A_CPU1_SA_DQ<28>")
	)
	(segment
		(start 85.043772 -266.372848)
		(end 85.076792 -266.405868)
		(width 0.088646)
		(layer "F.Cu")
		(net "M_A_CPU1_SA_DQ<28>")
	)
	(segment
		(start 73.832466 -280.20645)
		(end 73.949052 -280.089864)
		(width 0.1016)
		(layer "F.Cu")
		(net "M_A_CPU1_SA_DQ<28>")
	)
	(segment
		(start 83.391248 -267.370052)
		(end 83.785964 -266.975336)
		(width 0.088646)
		(layer "F.Cu")
		(net "M_A_CPU1_SA_DQ<28>")
	)
	(segment
		(start 67.326256 -282.89123)
		(end 68.11264 -282.89123)
		(width 0.20066)
		(layer "F.Cu")
		(net "M_A_CPU1_SA_DQ<28>")
	)
	(segment
		(start 56.401716 -281.89174)
		(end 56.665114 -281.89174)
		(width 0.101854)
		(layer "F.Cu")
		(net "M_A_CPU1_SA_DQ<28>")
	)
	(segment
		(start 63.951612 -281.884882)
		(end 64.154304 -281.884882)
		(width 0.101854)
		(layer "F.Cu")
		(net "M_A_CPU1_SA_DQ<28>")
	)
	(segment
		(start 68.418456 -282.585414)
		(end 68.702428 -282.585414)
		(width 0.20066)
		(layer "F.Cu")
		(net "M_A_CPU1_SA_DQ<28>")
	)
	(segment
		(start 84.757514 -266.495022)
		(end 84.879688 -266.372848)
		(width 0.088646)
		(layer "F.Cu")
		(net "M_A_CPU1_SA_DQ<28>")
	)
	(segment
		(start 59.199526 -281.89174)
		(end 59.624468 -282.316682)
		(width 0.20066)
		(layer "F.Cu")
		(net "M_A_CPU1_SA_DQ<28>")
	)
	(segment
		(start 64.176148 -281.89174)
		(end 65.855342 -281.89174)
		(width 0.1016)
		(layer "F.Cu")
		(net "M_A_CPU1_SA_DQ<28>")
	)
	(segment
		(start 84.879688 -266.372848)
		(end 85.043772 -266.372848)
		(width 0.088646)
		(layer "F.Cu")
		(net "M_A_CPU1_SA_DQ<28>")
	)
	(segment
		(start 71.32447 -282.714446)
		(end 73.832466 -280.20645)
		(width 0.20066)
		(layer "F.Cu")
		(net "M_A_CPU1_SA_DQ<28>")
	)
	(segment
		(start 61.44514 -282.316682)
		(end 61.82614 -281.935682)
		(width 0.20066)
		(layer "F.Cu")
		(net "M_A_CPU1_SA_DQ<28>")
	)
	(segment
		(start 68.982844 -282.86583)
		(end 69.554852 -282.86583)
		(width 0.20066)
		(layer "F.Cu")
		(net "M_A_CPU1_SA_DQ<28>")
	)
	(segment
		(start 74.510392 -279.660604)
		(end 74.510392 -279.550876)
		(width 0.1016)
		(layer "F.Cu")
		(net "M_A_CPU1_SA_DQ<28>")
	)
	(segment
		(start 66.745104 -282.100782)
		(end 66.891916 -282.45689)
		(width 0.20066)
		(layer "F.Cu")
		(net "M_A_CPU1_SA_DQ<28>")
	)
	(segment
		(start 84.069682 -266.697206)
		(end 84.342224 -266.424664)
		(width 0.088646)
		(layer "F.Cu")
		(net "M_A_CPU1_SA_DQ<28>")
	)
	(segment
		(start 63.52286 -281.884882)
		(end 63.951612 -281.884882)
		(width 0.20066)
		(layer "F.Cu")
		(net "M_A_CPU1_SA_DQ<28>")
	)
	(segment
		(start 74.594212 -280.076656)
		(end 74.594212 -279.744424)
		(width 0.1016)
		(layer "F.Cu")
		(net "M_A_CPU1_SA_DQ<28>")
	)
	(segment
		(start 63.14186 -282.421838)
		(end 63.440564 -281.906726)
		(width 0.20066)
		(layer "F.Cu")
		(net "M_A_CPU1_SA_DQ<28>")
	)
	(segment
		(start 62.480698 -282.10891)
		(end 62.532006 -282.302458)
		(width 0.20066)
		(layer "F.Cu")
		(net "M_A_CPU1_SA_DQ<28>")
	)
	(segment
		(start 85.076792 -266.405868)
		(end 85.435694 -266.405868)
		(width 0.088646)
		(layer "F.Cu")
		(net "M_A_CPU1_SA_DQ<28>")
	)
	(segment
		(start 74.88809 -279.173178)
		(end 75.400408 -276.597364)
		(width 0.1016)
		(layer "F.Cu")
		(net "M_A_CPU1_SA_DQ<28>")
	)
	(segment
		(start 83.881722 -266.975336)
		(end 84.069682 -266.787376)
		(width 0.088646)
		(layer "F.Cu")
		(net "M_A_CPU1_SA_DQ<28>")
	)
	(segment
		(start 66.891916 -282.45689)
		(end 67.326256 -282.89123)
		(width 0.20066)
		(layer "F.Cu")
		(net "M_A_CPU1_SA_DQ<28>")
	)
	(segment
		(start 74.594212 -279.744424)
		(end 74.510392 -279.660604)
		(width 0.1016)
		(layer "F.Cu")
		(net "M_A_CPU1_SA_DQ<28>")
	)
	(segment
		(start 63.440564 -281.906726)
		(end 63.52286 -281.884882)
		(width 0.20066)
		(layer "F.Cu")
		(net "M_A_CPU1_SA_DQ<28>")
	)
	(segment
		(start 62.255654 -281.935682)
		(end 62.480698 -282.10891)
		(width 0.20066)
		(layer "F.Cu")
		(net "M_A_CPU1_SA_DQ<28>")
	)
	(segment
		(start 70.12686 -282.578048)
		(end 70.263258 -282.714446)
		(width 0.20066)
		(layer "F.Cu")
		(net "M_A_CPU1_SA_DQ<28>")
	)
	(segment
		(start 68.11264 -282.89123)
		(end 68.418456 -282.585414)
		(width 0.20066)
		(layer "F.Cu")
		(net "M_A_CPU1_SA_DQ<28>")
	)
	(segment
		(start 56.37911 -281.874214)
		(end 56.38419 -281.874214)
		(width 0.101854)
		(layer "F.Cu")
		(net "M_A_CPU1_SA_DQ<28>")
	)
	(segment
		(start 74.2569 -280.253694)
		(end 74.417174 -280.253694)
		(width 0.1016)
		(layer "F.Cu")
		(net "M_A_CPU1_SA_DQ<28>")
	)
	(segment
		(start 55.06212 -281.874214)
		(end 56.37911 -281.874214)
		(width 0.20066)
		(layer "F.Cu")
		(net "M_A_CPU1_SA_DQ<28>")
	)
	(segment
		(start 83.785964 -266.975336)
		(end 83.881722 -266.975336)
		(width 0.088646)
		(layer "F.Cu")
		(net "M_A_CPU1_SA_DQ<28>")
	)
	(segment
		(start 59.624468 -282.316682)
		(end 60.947046 -282.316682)
		(width 0.20066)
		(layer "F.Cu")
		(net "M_A_CPU1_SA_DQ<28>")
	)
	(segment
		(start 69.842634 -282.578048)
		(end 70.12686 -282.578048)
		(width 0.20066)
		(layer "F.Cu")
		(net "M_A_CPU1_SA_DQ<28>")
	)
	(segment
		(start 84.538058 -266.495022)
		(end 84.757514 -266.495022)
		(width 0.088646)
		(layer "F.Cu")
		(net "M_A_CPU1_SA_DQ<28>")
	)
	(segment
		(start 66.161412 -281.882088)
		(end 66.446654 -281.882088)
		(width 0.20066)
		(layer "F.Cu")
		(net "M_A_CPU1_SA_DQ<28>")
	)
	(segment
		(start 65.855342 -281.89174)
		(end 65.898268 -281.882088)
		(width 0.1016)
		(layer "F.Cu")
		(net "M_A_CPU1_SA_DQ<28>")
	)
	(segment
		(start 62.865 -282.495498)
		(end 63.14186 -282.421838)
		(width 0.20066)
		(layer "F.Cu")
		(net "M_A_CPU1_SA_DQ<28>")
	)
	(segment
		(start 84.342224 -266.424664)
		(end 84.4677 -266.424664)
		(width 0.088646)
		(layer "F.Cu")
		(net "M_A_CPU1_SA_DQ<28>")
	)
	(segment
		(start 73.949052 -280.089864)
		(end 74.09307 -280.089864)
		(width 0.1016)
		(layer "F.Cu")
		(net "M_A_CPU1_SA_DQ<28>")
	)
	(segment
		(start 54.248558 -282.316682)
		(end 54.45633 -282.524454)
		(width 0.20066)
		(layer "F.Cu")
		(net "M_A_CPU1_SA_DQ<28>")
	)
	(segment
		(start 58.704226 -281.89174)
		(end 59.199526 -281.89174)
		(width 0.20066)
		(layer "F.Cu")
		(net "M_A_CPU1_SA_DQ<28>")
	)
	(segment
		(start 54.751986 -282.524454)
		(end 54.958234 -282.318206)
		(width 0.20066)
		(layer "F.Cu")
		(net "M_A_CPU1_SA_DQ<28>")
	)
	(segment
		(start 84.4677 -266.424664)
		(end 84.538058 -266.495022)
		(width 0.088646)
		(layer "F.Cu")
		(net "M_A_CPU1_SA_DQ<28>")
	)
	(segment
		(start 54.958234 -282.318206)
		(end 54.958234 -281.9781)
		(width 0.20066)
		(layer "F.Cu")
		(net "M_A_CPU1_SA_DQ<28>")
	)
	(segment
		(start 54.45633 -282.524454)
		(end 54.751986 -282.524454)
		(width 0.20066)
		(layer "F.Cu")
		(net "M_A_CPU1_SA_DQ<28>")
	)
	(segment
		(start 65.898268 -281.882088)
		(end 66.161412 -281.882088)
		(width 0.101854)
		(layer "F.Cu")
		(net "M_A_CPU1_SA_DQ<28>")
	)
	(segment
		(start 64.154304 -281.884882)
		(end 64.176148 -281.89174)
		(width 0.1016)
		(layer "F.Cu")
		(net "M_A_CPU1_SA_DQ<28>")
	)
	(segment
		(start 74.09307 -280.089864)
		(end 74.2569 -280.253694)
		(width 0.1016)
		(layer "F.Cu")
		(net "M_A_CPU1_SA_DQ<28>")
	)
	(segment
		(start 69.554852 -282.86583)
		(end 69.842634 -282.578048)
		(width 0.20066)
		(layer "F.Cu")
		(net "M_A_CPU1_SA_DQ<28>")
	)
	(segment
		(start 56.665114 -281.89174)
		(end 58.643012 -281.89174)
		(width 0.1016)
		(layer "F.Cu")
		(net "M_A_CPU1_SA_DQ<28>")
	)
	(segment
		(start 70.263258 -282.714446)
		(end 71.32447 -282.714446)
		(width 0.20066)
		(layer "F.Cu")
		(net "M_A_CPU1_SA_DQ<28>")
	)
	(segment
		(start 61.82614 -281.935682)
		(end 62.255654 -281.935682)
		(width 0.20066)
		(layer "F.Cu")
		(net "M_A_CPU1_SA_DQ<28>")
	)
	(segment
		(start 74.510392 -279.550876)
		(end 74.88809 -279.173178)
		(width 0.1016)
		(layer "F.Cu")
		(net "M_A_CPU1_SA_DQ<28>")
	)
	(segment
		(start 58.643012 -281.89174)
		(end 58.704226 -281.89174)
		(width 0.101854)
		(layer "F.Cu")
		(net "M_A_CPU1_SA_DQ<28>")
	)
	(segment
		(start 60.01512 -286.15767)
		(end 60.06338 -286.141668)
		(width 0.1016)
		(layer "F.Cu")
		(net "M_A_CPU1_SA_DQ<27>")
	)
	(segment
		(start 84.625688 -268.265148)
		(end 84.47913 -268.411706)
		(width 0.088646)
		(layer "F.Cu")
		(net "M_A_CPU1_SA_DQ<27>")
	)
	(segment
		(start 62.855602 -285.599124)
		(end 63.126366 -285.599124)
		(width 0.20066)
		(layer "F.Cu")
		(net "M_A_CPU1_SA_DQ<27>")
	)
	(segment
		(start 75.82789 -282.559252)
		(end 75.517248 -282.559252)
		(width 0.1016)
		(layer "F.Cu")
		(net "M_A_CPU1_SA_DQ<27>")
	)
	(segment
		(start 85.29828 -267.657326)
		(end 85.051392 -267.814806)
		(width 0.088646)
		(layer "F.Cu")
		(net "M_A_CPU1_SA_DQ<27>")
	)
	(segment
		(start 85.051392 -267.814806)
		(end 84.982304 -267.883894)
		(width 0.088646)
		(layer "F.Cu")
		(net "M_A_CPU1_SA_DQ<27>")
	)
	(segment
		(start 84.47913 -268.59865)
		(end 84.305902 -268.771878)
		(width 0.088646)
		(layer "F.Cu")
		(net "M_A_CPU1_SA_DQ<27>")
	)
	(segment
		(start 84.982304 -268.095476)
		(end 84.812632 -268.265148)
		(width 0.088646)
		(layer "F.Cu")
		(net "M_A_CPU1_SA_DQ<27>")
	)
	(segment
		(start 84.47913 -268.411706)
		(end 84.47913 -268.59865)
		(width 0.088646)
		(layer "F.Cu")
		(net "M_A_CPU1_SA_DQ<27>")
	)
	(segment
		(start 72.164956 -285.911544)
		(end 71.916036 -285.911544)
		(width 0.20066)
		(layer "F.Cu")
		(net "M_A_CPU1_SA_DQ<27>")
	)
	(segment
		(start 87.128096 -267.709396)
		(end 87.113364 -267.718032)
		(width 0.088646)
		(layer "F.Cu")
		(net "M_A_CPU1_SA_DQ<27>")
	)
	(segment
		(start 75.950826 -282.240736)
		(end 75.950826 -282.436316)
		(width 0.1016)
		(layer "F.Cu")
		(net "M_A_CPU1_SA_DQ<27>")
	)
	(segment
		(start 61.789056 -286.141668)
		(end 61.881258 -286.16021)
		(width 0.1016)
		(layer "F.Cu")
		(net "M_A_CPU1_SA_DQ<27>")
	)
	(segment
		(start 78.096364 -274.822412)
		(end 76.89215 -277.075138)
		(width 0.1016)
		(layer "F.Cu")
		(net "M_A_CPU1_SA_DQ<27>")
	)
	(segment
		(start 87.315294 -268.033754)
		(end 87.660988 -268.033754)
		(width 0.088646)
		(layer "F.Cu")
		(net "M_A_CPU1_SA_DQ<27>")
	)
	(segment
		(start 66.60007 -285.911544)
		(end 66.403982 -285.715456)
		(width 0.20066)
		(layer "F.Cu")
		(net "M_A_CPU1_SA_DQ<27>")
	)
	(segment
		(start 83.961986 -268.95679)
		(end 78.096364 -274.822412)
		(width 0.1016)
		(layer "F.Cu")
		(net "M_A_CPU1_SA_DQ<27>")
	)
	(segment
		(start 62.147958 -286.16021)
		(end 62.546484 -286.16021)
		(width 0.20066)
		(layer "F.Cu")
		(net "M_A_CPU1_SA_DQ<27>")
	)
	(segment
		(start 84.982304 -267.883894)
		(end 84.982304 -268.095476)
		(width 0.088646)
		(layer "F.Cu")
		(net "M_A_CPU1_SA_DQ<27>")
	)
	(segment
		(start 66.243708 -285.715456)
		(end 65.949322 -286.009842)
		(width 0.20066)
		(layer "F.Cu")
		(net "M_A_CPU1_SA_DQ<27>")
	)
	(segment
		(start 71.64197 -285.637478)
		(end 71.365618 -285.637478)
		(width 0.20066)
		(layer "F.Cu")
		(net "M_A_CPU1_SA_DQ<27>")
	)
	(segment
		(start 71.365618 -285.637478)
		(end 71.091552 -285.911544)
		(width 0.20066)
		(layer "F.Cu")
		(net "M_A_CPU1_SA_DQ<27>")
	)
	(segment
		(start 65.80124 -286.009842)
		(end 65.50787 -285.716472)
		(width 0.20066)
		(layer "F.Cu")
		(net "M_A_CPU1_SA_DQ<27>")
	)
	(segment
		(start 71.916036 -285.911544)
		(end 71.64197 -285.637478)
		(width 0.20066)
		(layer "F.Cu")
		(net "M_A_CPU1_SA_DQ<27>")
	)
	(segment
		(start 63.471044 -285.943802)
		(end 64.226694 -285.943802)
		(width 0.20066)
		(layer "F.Cu")
		(net "M_A_CPU1_SA_DQ<27>")
	)
	(segment
		(start 59.822842 -286.15767)
		(end 60.01512 -286.15767)
		(width 0.101854)
		(layer "F.Cu")
		(net "M_A_CPU1_SA_DQ<27>")
	)
	(segment
		(start 75.853036 -281.826716)
		(end 75.853036 -282.142946)
		(width 0.1016)
		(layer "F.Cu")
		(net "M_A_CPU1_SA_DQ<27>")
	)
	(segment
		(start 57.503314 -285.716726)
		(end 58.973466 -285.716726)
		(width 0.20066)
		(layer "F.Cu")
		(net "M_A_CPU1_SA_DQ<27>")
	)
	(segment
		(start 87.660988 -267.64615)
		(end 87.287608 -267.64615)
		(width 0.088646)
		(layer "F.Cu")
		(net "M_A_CPU1_SA_DQ<27>")
	)
	(segment
		(start 62.71006 -285.996634)
		(end 62.71006 -285.744666)
		(width 0.20066)
		(layer "F.Cu")
		(net "M_A_CPU1_SA_DQ<27>")
	)
	(segment
		(start 61.881258 -286.16021)
		(end 62.147958 -286.16021)
		(width 0.101854)
		(layer "F.Cu")
		(net "M_A_CPU1_SA_DQ<27>")
	)
	(segment
		(start 65.50787 -285.716472)
		(end 65.507616 -285.716726)
		(width 0.20066)
		(layer "F.Cu")
		(net "M_A_CPU1_SA_DQ<27>")
	)
	(segment
		(start 59.41441 -286.15767)
		(end 59.822842 -286.15767)
		(width 0.20066)
		(layer "F.Cu")
		(net "M_A_CPU1_SA_DQ<27>")
	)
	(segment
		(start 85.957918 -267.902182)
		(end 85.795104 -267.902182)
		(width 0.088646)
		(layer "F.Cu")
		(net "M_A_CPU1_SA_DQ<27>")
	)
	(segment
		(start 85.550248 -267.657326)
		(end 85.29828 -267.657326)
		(width 0.088646)
		(layer "F.Cu")
		(net "M_A_CPU1_SA_DQ<27>")
	)
	(segment
		(start 84.305902 -268.771878)
		(end 84.146898 -268.771878)
		(width 0.088646)
		(layer "F.Cu")
		(net "M_A_CPU1_SA_DQ<27>")
	)
	(segment
		(start 62.71006 -285.744666)
		(end 62.855602 -285.599124)
		(width 0.20066)
		(layer "F.Cu")
		(net "M_A_CPU1_SA_DQ<27>")
	)
	(segment
		(start 76.89215 -277.075138)
		(end 75.969876 -281.709876)
		(width 0.1016)
		(layer "F.Cu")
		(net "M_A_CPU1_SA_DQ<27>")
	)
	(segment
		(start 58.973466 -285.716726)
		(end 59.41441 -286.15767)
		(width 0.20066)
		(layer "F.Cu")
		(net "M_A_CPU1_SA_DQ<27>")
	)
	(segment
		(start 65.949322 -286.009842)
		(end 65.80124 -286.009842)
		(width 0.20066)
		(layer "F.Cu")
		(net "M_A_CPU1_SA_DQ<27>")
	)
	(segment
		(start 85.795104 -267.902182)
		(end 85.550248 -267.657326)
		(width 0.088646)
		(layer "F.Cu")
		(net "M_A_CPU1_SA_DQ<27>")
	)
	(segment
		(start 87.749634 -267.945108)
		(end 87.749634 -267.734796)
		(width 0.088646)
		(layer "F.Cu")
		(net "M_A_CPU1_SA_DQ<27>")
	)
	(segment
		(start 60.06338 -286.141668)
		(end 61.789056 -286.141668)
		(width 0.1016)
		(layer "F.Cu")
		(net "M_A_CPU1_SA_DQ<27>")
	)
	(segment
		(start 64.454278 -285.716726)
		(end 65.047114 -285.716726)
		(width 0.20066)
		(layer "F.Cu")
		(net "M_A_CPU1_SA_DQ<27>")
	)
	(segment
		(start 75.853036 -282.142946)
		(end 75.950826 -282.240736)
		(width 0.1016)
		(layer "F.Cu")
		(net "M_A_CPU1_SA_DQ<27>")
	)
	(segment
		(start 84.812632 -268.265148)
		(end 84.625688 -268.265148)
		(width 0.088646)
		(layer "F.Cu")
		(net "M_A_CPU1_SA_DQ<27>")
	)
	(segment
		(start 62.546484 -286.16021)
		(end 62.71006 -285.996634)
		(width 0.20066)
		(layer "F.Cu")
		(net "M_A_CPU1_SA_DQ<27>")
	)
	(segment
		(start 86.369906 -267.596366)
		(end 86.263734 -267.596366)
		(width 0.088646)
		(layer "F.Cu")
		(net "M_A_CPU1_SA_DQ<27>")
	)
	(segment
		(start 75.969876 -281.709876)
		(end 75.853036 -281.826716)
		(width 0.1016)
		(layer "F.Cu")
		(net "M_A_CPU1_SA_DQ<27>")
	)
	(segment
		(start 75.517248 -282.559252)
		(end 72.164956 -285.911544)
		(width 0.20066)
		(layer "F.Cu")
		(net "M_A_CPU1_SA_DQ<27>")
	)
	(segment
		(start 64.226694 -285.943802)
		(end 64.454024 -285.716472)
		(width 0.20066)
		(layer "F.Cu")
		(net "M_A_CPU1_SA_DQ<27>")
	)
	(segment
		(start 66.403982 -285.715456)
		(end 66.243708 -285.715456)
		(width 0.20066)
		(layer "F.Cu")
		(net "M_A_CPU1_SA_DQ<27>")
	)
	(segment
		(start 71.091552 -285.911544)
		(end 66.60007 -285.911544)
		(width 0.20066)
		(layer "F.Cu")
		(net "M_A_CPU1_SA_DQ<27>")
	)
	(segment
		(start 86.562692 -267.709396)
		(end 86.369906 -267.596366)
		(width 0.088646)
		(layer "F.Cu")
		(net "M_A_CPU1_SA_DQ<27>")
	)
	(segment
		(start 86.263734 -267.596366)
		(end 85.957918 -267.902182)
		(width 0.088646)
		(layer "F.Cu")
		(net "M_A_CPU1_SA_DQ<27>")
	)
	(segment
		(start 75.950826 -282.436316)
		(end 75.82789 -282.559252)
		(width 0.1016)
		(layer "F.Cu")
		(net "M_A_CPU1_SA_DQ<27>")
	)
	(segment
		(start 65.507616 -285.716726)
		(end 65.047114 -285.716726)
		(width 0.20066)
		(layer "F.Cu")
		(net "M_A_CPU1_SA_DQ<27>")
	)
	(segment
		(start 84.146898 -268.771878)
		(end 83.961986 -268.95679)
		(width 0.088646)
		(layer "F.Cu")
		(net "M_A_CPU1_SA_DQ<27>")
	)
	(segment
		(start 63.126366 -285.599124)
		(end 63.471044 -285.943802)
		(width 0.20066)
		(layer "F.Cu")
		(net "M_A_CPU1_SA_DQ<27>")
	)
	(segment
		(start 64.454024 -285.716472)
		(end 64.454278 -285.716726)
		(width 0.20066)
		(layer "F.Cu")
		(net "M_A_CPU1_SA_DQ<27>")
	)
	(arc
		(start 87.201502 -267.66774)
		(mid 87.164625 -267.688261)
		(end 87.128096 -267.709396)
		(width 0.088646)
		(layer "F.Cu")
		(net "M_A_CPU1_SA_DQ<27>")
	)
	(arc
		(start 87.660988 -268.033754)
		(mid 87.72367 -268.00779)
		(end 87.749634 -267.945108)
		(width 0.088646)
		(layer "F.Cu")
		(net "M_A_CPU1_SA_DQ<27>")
	)
	(arc
		(start 87.113364 -267.718032)
		(mid 86.836889 -267.785352)
		(end 86.562692 -267.709396)
		(width 0.088646)
		(layer "F.Cu")
		(net "M_A_CPU1_SA_DQ<27>")
	)
	(arc
		(start 87.749634 -267.734796)
		(mid 87.72367 -267.672114)
		(end 87.660988 -267.64615)
		(width 0.088646)
		(layer "F.Cu")
		(net "M_A_CPU1_SA_DQ<27>")
	)
	(arc
		(start 87.287608 -267.64615)
		(mid 87.243205 -267.651565)
		(end 87.201502 -267.66774)
		(width 0.088646)
		(layer "F.Cu")
		(net "M_A_CPU1_SA_DQ<27>")
	)
	(segment
		(start 87.007954 -269.378176)
		(end 86.600792 -269.378176)
		(width 0.088646)
		(layer "F.Cu")
		(net "M_A_CPU1_SA_DQ<26>")
	)
	(segment
		(start 85.167216 -269.018766)
		(end 84.763102 -269.018766)
		(width 0.088646)
		(layer "F.Cu")
		(net "M_A_CPU1_SA_DQ<26>")
	)
	(segment
		(start 86.600792 -269.378176)
		(end 86.352126 -269.12951)
		(width 0.088646)
		(layer "F.Cu")
		(net "M_A_CPU1_SA_DQ<26>")
	)
	(segment
		(start 86.352126 -268.571726)
		(end 86.009226 -268.228826)
		(width 0.088646)
		(layer "F.Cu")
		(net "M_A_CPU1_SA_DQ<26>")
	)
	(segment
		(start 59.822842 -286.983932)
		(end 60.051696 -286.983932)
		(width 0.101854)
		(layer "F.Cu")
		(net "M_A_CPU1_SA_DQ<26>")
	)
	(segment
		(start 63.330328 -287.416494)
		(end 63.330582 -287.416748)
		(width 0.20066)
		(layer "F.Cu")
		(net "M_A_CPU1_SA_DQ<26>")
	)
	(segment
		(start 78.590902 -275.190966)
		(end 77.47254 -277.283672)
		(width 0.1016)
		(layer "F.Cu")
		(net "M_A_CPU1_SA_DQ<26>")
	)
	(segment
		(start 76.560426 -283.336238)
		(end 76.00823 -283.888434)
		(width 0.1016)
		(layer "F.Cu")
		(net "M_A_CPU1_SA_DQ<26>")
	)
	(segment
		(start 86.352126 -269.12951)
		(end 86.352126 -268.571726)
		(width 0.088646)
		(layer "F.Cu")
		(net "M_A_CPU1_SA_DQ<26>")
	)
	(segment
		(start 62.869826 -287.551622)
		(end 63.1952 -287.551622)
		(width 0.20066)
		(layer "F.Cu")
		(net "M_A_CPU1_SA_DQ<26>")
	)
	(segment
		(start 57.503314 -287.416748)
		(end 58.768234 -287.416748)
		(width 0.20066)
		(layer "F.Cu")
		(net "M_A_CPU1_SA_DQ<26>")
	)
	(segment
		(start 76.00823 -283.888434)
		(end 72.664066 -287.232598)
		(width 0.20066)
		(layer "F.Cu")
		(net "M_A_CPU1_SA_DQ<26>")
	)
	(segment
		(start 62.72276 -287.118552)
		(end 62.72276 -287.404556)
		(width 0.20066)
		(layer "F.Cu")
		(net "M_A_CPU1_SA_DQ<26>")
	)
	(segment
		(start 62.72276 -287.404556)
		(end 62.869826 -287.551622)
		(width 0.20066)
		(layer "F.Cu")
		(net "M_A_CPU1_SA_DQ<26>")
	)
	(segment
		(start 84.763102 -269.018766)
		(end 83.961732 -269.820136)
		(width 0.088646)
		(layer "F.Cu")
		(net "M_A_CPU1_SA_DQ<26>")
	)
	(segment
		(start 60.076334 -286.991552)
		(end 62.116462 -286.991552)
		(width 0.1016)
		(layer "F.Cu")
		(net "M_A_CPU1_SA_DQ<26>")
	)
	(segment
		(start 85.294216 -268.559026)
		(end 85.294216 -268.891766)
		(width 0.088646)
		(layer "F.Cu")
		(net "M_A_CPU1_SA_DQ<26>")
	)
	(segment
		(start 76.560426 -281.867864)
		(end 76.560426 -283.336238)
		(width 0.1016)
		(layer "F.Cu")
		(net "M_A_CPU1_SA_DQ<26>")
	)
	(segment
		(start 87.057484 -268.84757)
		(end 87.168482 -268.958568)
		(width 0.088646)
		(layer "F.Cu")
		(net "M_A_CPU1_SA_DQ<26>")
	)
	(segment
		(start 58.768234 -287.416748)
		(end 58.886852 -287.29813)
		(width 0.20066)
		(layer "F.Cu")
		(net "M_A_CPU1_SA_DQ<26>")
	)
	(segment
		(start 63.330582 -287.416748)
		(end 65.047114 -287.416748)
		(width 0.20066)
		(layer "F.Cu")
		(net "M_A_CPU1_SA_DQ<26>")
	)
	(segment
		(start 85.780626 -268.228826)
		(end 85.577426 -268.432026)
		(width 0.088646)
		(layer "F.Cu")
		(net "M_A_CPU1_SA_DQ<26>")
	)
	(segment
		(start 62.13094 -286.977074)
		(end 62.147958 -286.977074)
		(width 0.101854)
		(layer "F.Cu")
		(net "M_A_CPU1_SA_DQ<26>")
	)
	(segment
		(start 62.147958 -286.977074)
		(end 62.581282 -286.977074)
		(width 0.20066)
		(layer "F.Cu")
		(net "M_A_CPU1_SA_DQ<26>")
	)
	(segment
		(start 62.581282 -286.977074)
		(end 62.72276 -287.118552)
		(width 0.20066)
		(layer "F.Cu")
		(net "M_A_CPU1_SA_DQ<26>")
	)
	(segment
		(start 62.116462 -286.991552)
		(end 62.13094 -286.977074)
		(width 0.101854)
		(layer "F.Cu")
		(net "M_A_CPU1_SA_DQ<26>")
	)
	(segment
		(start 58.886852 -287.124902)
		(end 59.027822 -286.983932)
		(width 0.20066)
		(layer "F.Cu")
		(net "M_A_CPU1_SA_DQ<26>")
	)
	(segment
		(start 77.47254 -277.283672)
		(end 76.560426 -281.867864)
		(width 0.1016)
		(layer "F.Cu")
		(net "M_A_CPU1_SA_DQ<26>")
	)
	(segment
		(start 63.1952 -287.551622)
		(end 63.330328 -287.416494)
		(width 0.20066)
		(layer "F.Cu")
		(net "M_A_CPU1_SA_DQ<26>")
	)
	(segment
		(start 85.294216 -268.891766)
		(end 85.167216 -269.018766)
		(width 0.088646)
		(layer "F.Cu")
		(net "M_A_CPU1_SA_DQ<26>")
	)
	(segment
		(start 83.961732 -269.820136)
		(end 78.590902 -275.190966)
		(width 0.1016)
		(layer "F.Cu")
		(net "M_A_CPU1_SA_DQ<26>")
	)
	(segment
		(start 59.027822 -286.983932)
		(end 59.822842 -286.983932)
		(width 0.20066)
		(layer "F.Cu")
		(net "M_A_CPU1_SA_DQ<26>")
	)
	(segment
		(start 58.886852 -287.29813)
		(end 58.886852 -287.124902)
		(width 0.20066)
		(layer "F.Cu")
		(net "M_A_CPU1_SA_DQ<26>")
	)
	(segment
		(start 87.168482 -269.217648)
		(end 87.007954 -269.378176)
		(width 0.088646)
		(layer "F.Cu")
		(net "M_A_CPU1_SA_DQ<26>")
	)
	(segment
		(start 66.951352 -287.416748)
		(end 65.047114 -287.416748)
		(width 0.20066)
		(layer "F.Cu")
		(net "M_A_CPU1_SA_DQ<26>")
	)
	(segment
		(start 72.664066 -287.232598)
		(end 67.135502 -287.232598)
		(width 0.20066)
		(layer "F.Cu")
		(net "M_A_CPU1_SA_DQ<26>")
	)
	(segment
		(start 86.009226 -268.228826)
		(end 85.780626 -268.228826)
		(width 0.088646)
		(layer "F.Cu")
		(net "M_A_CPU1_SA_DQ<26>")
	)
	(segment
		(start 60.051696 -286.983932)
		(end 60.076334 -286.991552)
		(width 0.1016)
		(layer "F.Cu")
		(net "M_A_CPU1_SA_DQ<26>")
	)
	(segment
		(start 67.135502 -287.232598)
		(end 66.951352 -287.416748)
		(width 0.20066)
		(layer "F.Cu")
		(net "M_A_CPU1_SA_DQ<26>")
	)
	(segment
		(start 85.421216 -268.432026)
		(end 85.294216 -268.559026)
		(width 0.088646)
		(layer "F.Cu")
		(net "M_A_CPU1_SA_DQ<26>")
	)
	(segment
		(start 87.168482 -268.958568)
		(end 87.168482 -269.217648)
		(width 0.088646)
		(layer "F.Cu")
		(net "M_A_CPU1_SA_DQ<26>")
	)
	(segment
		(start 85.577426 -268.432026)
		(end 85.421216 -268.432026)
		(width 0.088646)
		(layer "F.Cu")
		(net "M_A_CPU1_SA_DQ<26>")
	)
	(segment
		(start 86.845648 -268.84757)
		(end 87.057484 -268.84757)
		(width 0.088646)
		(layer "F.Cu")
		(net "M_A_CPU1_SA_DQ<26>")
	)
	(segment
		(start 78.343506 -275.00707)
		(end 83.746086 -269.60449)
		(width 0.1016)
		(layer "F.Cu")
		(net "M_A_CPU1_SA_DQ<25>")
	)
	(segment
		(start 66.832734 -286.551116)
		(end 72.430132 -286.551116)
		(width 0.20066)
		(layer "F.Cu")
		(net "M_A_CPU1_SA_DQ<25>")
	)
	(segment
		(start 83.746086 -269.60449)
		(end 85.316822 -268.033754)
		(width 0.088646)
		(layer "F.Cu")
		(net "M_A_CPU1_SA_DQ<25>")
	)
	(segment
		(start 76.099162 -282.882086)
		(end 76.255626 -282.504134)
		(width 0.1016)
		(layer "F.Cu")
		(net "M_A_CPU1_SA_DQ<25>")
	)
	(segment
		(start 75.550522 -283.430726)
		(end 76.099162 -282.882086)
		(width 0.1016)
		(layer "F.Cu")
		(net "M_A_CPU1_SA_DQ<25>")
	)
	(segment
		(start 54.027324 -286.566356)
		(end 54.279292 -286.818324)
		(width 0.20066)
		(layer "F.Cu")
		(net "M_A_CPU1_SA_DQ<25>")
	)
	(segment
		(start 56.436006 -286.127444)
		(end 56.45023 -286.141668)
		(width 0.101854)
		(layer "F.Cu")
		(net "M_A_CPU1_SA_DQ<25>")
	)
	(segment
		(start 60.947046 -286.56661)
		(end 63.14059 -286.56661)
		(width 0.20066)
		(layer "F.Cu")
		(net "M_A_CPU1_SA_DQ<25>")
	)
	(segment
		(start 63.580264 -287.006284)
		(end 63.92291 -287.006284)
		(width 0.20066)
		(layer "F.Cu")
		(net "M_A_CPU1_SA_DQ<25>")
	)
	(segment
		(start 58.693812 -286.141668)
		(end 58.704226 -286.141668)
		(width 0.101854)
		(layer "F.Cu")
		(net "M_A_CPU1_SA_DQ<25>")
	)
	(segment
		(start 54.897528 -286.584136)
		(end 54.897528 -286.2961)
		(width 0.20066)
		(layer "F.Cu")
		(net "M_A_CPU1_SA_DQ<25>")
	)
	(segment
		(start 63.14059 -286.56661)
		(end 63.580264 -287.006284)
		(width 0.20066)
		(layer "F.Cu")
		(net "M_A_CPU1_SA_DQ<25>")
	)
	(segment
		(start 56.45023 -286.141668)
		(end 58.693812 -286.141668)
		(width 0.1016)
		(layer "F.Cu")
		(net "M_A_CPU1_SA_DQ<25>")
	)
	(segment
		(start 59.24042 -286.56661)
		(end 60.947046 -286.56661)
		(width 0.20066)
		(layer "F.Cu")
		(net "M_A_CPU1_SA_DQ<25>")
	)
	(segment
		(start 77.182472 -277.179532)
		(end 78.343506 -275.00707)
		(width 0.1016)
		(layer "F.Cu")
		(net "M_A_CPU1_SA_DQ<25>")
	)
	(segment
		(start 63.92291 -287.006284)
		(end 63.988442 -287.006284)
		(width 0.101854)
		(layer "F.Cu")
		(net "M_A_CPU1_SA_DQ<25>")
	)
	(segment
		(start 55.066184 -286.127444)
		(end 56.37911 -286.127444)
		(width 0.20066)
		(layer "F.Cu")
		(net "M_A_CPU1_SA_DQ<25>")
	)
	(segment
		(start 56.37911 -286.127444)
		(end 56.436006 -286.127444)
		(width 0.101854)
		(layer "F.Cu")
		(net "M_A_CPU1_SA_DQ<25>")
	)
	(segment
		(start 54.02707 -286.56661)
		(end 54.027324 -286.566356)
		(width 0.20066)
		(layer "F.Cu")
		(net "M_A_CPU1_SA_DQ<25>")
	)
	(segment
		(start 66.44767 -286.93618)
		(end 66.832734 -286.551116)
		(width 0.20066)
		(layer "F.Cu")
		(net "M_A_CPU1_SA_DQ<25>")
	)
	(segment
		(start 63.988442 -287.006284)
		(end 64.003174 -286.991552)
		(width 0.101854)
		(layer "F.Cu")
		(net "M_A_CPU1_SA_DQ<25>")
	)
	(segment
		(start 54.897528 -286.2961)
		(end 55.066184 -286.127444)
		(width 0.20066)
		(layer "F.Cu")
		(net "M_A_CPU1_SA_DQ<25>")
	)
	(segment
		(start 54.279292 -286.818324)
		(end 54.66334 -286.818324)
		(width 0.20066)
		(layer "F.Cu")
		(net "M_A_CPU1_SA_DQ<25>")
	)
	(segment
		(start 53.403246 -286.56661)
		(end 54.02707 -286.56661)
		(width 0.20066)
		(layer "F.Cu")
		(net "M_A_CPU1_SA_DQ<25>")
	)
	(segment
		(start 54.66334 -286.818324)
		(end 54.897528 -286.584136)
		(width 0.20066)
		(layer "F.Cu")
		(net "M_A_CPU1_SA_DQ<25>")
	)
	(segment
		(start 64.003174 -286.991552)
		(end 66.248026 -286.991552)
		(width 0.1016)
		(layer "F.Cu")
		(net "M_A_CPU1_SA_DQ<25>")
	)
	(segment
		(start 66.248026 -286.991552)
		(end 66.313812 -286.991552)
		(width 0.20066)
		(layer "F.Cu")
		(net "M_A_CPU1_SA_DQ<25>")
	)
	(segment
		(start 58.704226 -286.141668)
		(end 58.815478 -286.141668)
		(width 0.20066)
		(layer "F.Cu")
		(net "M_A_CPU1_SA_DQ<25>")
	)
	(segment
		(start 76.255626 -282.504134)
		(end 76.255626 -281.837384)
		(width 0.1016)
		(layer "F.Cu")
		(net "M_A_CPU1_SA_DQ<25>")
	)
	(segment
		(start 66.313812 -286.991552)
		(end 66.44767 -286.93618)
		(width 0.20066)
		(layer "F.Cu")
		(net "M_A_CPU1_SA_DQ<25>")
	)
	(segment
		(start 58.815478 -286.141668)
		(end 59.24042 -286.56661)
		(width 0.20066)
		(layer "F.Cu")
		(net "M_A_CPU1_SA_DQ<25>")
	)
	(segment
		(start 76.255626 -281.837384)
		(end 77.182472 -277.179532)
		(width 0.1016)
		(layer "F.Cu")
		(net "M_A_CPU1_SA_DQ<25>")
	)
	(segment
		(start 72.430132 -286.551116)
		(end 75.550522 -283.430726)
		(width 0.20066)
		(layer "F.Cu")
		(net "M_A_CPU1_SA_DQ<25>")
	)
	(segment
		(start 85.316822 -268.033754)
		(end 85.435694 -268.033754)
		(width 0.088646)
		(layer "F.Cu")
		(net "M_A_CPU1_SA_DQ<25>")
	)
	(segment
		(start 54.279292 -288.518346)
		(end 54.66334 -288.518346)
		(width 0.20066)
		(layer "F.Cu")
		(net "M_A_CPU1_SA_DQ<24>")
	)
	(segment
		(start 63.701422 -287.82137)
		(end 63.02883 -288.049462)
		(width 0.20066)
		(layer "F.Cu")
		(net "M_A_CPU1_SA_DQ<24>")
	)
	(segment
		(start 56.44896 -287.826196)
		(end 56.464454 -287.84169)
		(width 0.101854)
		(layer "F.Cu")
		(net "M_A_CPU1_SA_DQ<24>")
	)
	(segment
		(start 54.897528 -288.284158)
		(end 54.897528 -287.996122)
		(width 0.20066)
		(layer "F.Cu")
		(net "M_A_CPU1_SA_DQ<24>")
	)
	(segment
		(start 54.02707 -288.266632)
		(end 54.027324 -288.266378)
		(width 0.20066)
		(layer "F.Cu")
		(net "M_A_CPU1_SA_DQ<24>")
	)
	(segment
		(start 63.951612 -287.82137)
		(end 63.701422 -287.82137)
		(width 0.20066)
		(layer "F.Cu")
		(net "M_A_CPU1_SA_DQ<24>")
	)
	(segment
		(start 76.865226 -283.936694)
		(end 76.460858 -284.341062)
		(width 0.1016)
		(layer "F.Cu")
		(net "M_A_CPU1_SA_DQ<24>")
	)
	(segment
		(start 58.704226 -287.826958)
		(end 59.083448 -287.826958)
		(width 0.20066)
		(layer "F.Cu")
		(net "M_A_CPU1_SA_DQ<24>")
	)
	(segment
		(start 63.02883 -288.049462)
		(end 62.034674 -288.266632)
		(width 0.20066)
		(layer "F.Cu")
		(net "M_A_CPU1_SA_DQ<24>")
	)
	(segment
		(start 62.034674 -288.266632)
		(end 60.947046 -288.266632)
		(width 0.20066)
		(layer "F.Cu")
		(net "M_A_CPU1_SA_DQ<24>")
	)
	(segment
		(start 85.905594 -268.84757)
		(end 85.500718 -269.252446)
		(width 0.088646)
		(layer "F.Cu")
		(net "M_A_CPU1_SA_DQ<24>")
	)
	(segment
		(start 66.237612 -287.84169)
		(end 64.12738 -287.84169)
		(width 0.1016)
		(layer "F.Cu")
		(net "M_A_CPU1_SA_DQ<24>")
	)
	(segment
		(start 84.960714 -269.252446)
		(end 84.177378 -270.035782)
		(width 0.088646)
		(layer "F.Cu")
		(net "M_A_CPU1_SA_DQ<24>")
	)
	(segment
		(start 53.403246 -288.266632)
		(end 54.02707 -288.266632)
		(width 0.20066)
		(layer "F.Cu")
		(net "M_A_CPU1_SA_DQ<24>")
	)
	(segment
		(start 78.838298 -275.374862)
		(end 77.76337 -277.386288)
		(width 0.1016)
		(layer "F.Cu")
		(net "M_A_CPU1_SA_DQ<24>")
	)
	(segment
		(start 59.083448 -287.826958)
		(end 59.523122 -288.266632)
		(width 0.20066)
		(layer "F.Cu")
		(net "M_A_CPU1_SA_DQ<24>")
	)
	(segment
		(start 85.500718 -269.252446)
		(end 84.960714 -269.252446)
		(width 0.088646)
		(layer "F.Cu")
		(net "M_A_CPU1_SA_DQ<24>")
	)
	(segment
		(start 58.684414 -287.826958)
		(end 58.704226 -287.826958)
		(width 0.101854)
		(layer "F.Cu")
		(net "M_A_CPU1_SA_DQ<24>")
	)
	(segment
		(start 84.177378 -270.035782)
		(end 78.838298 -275.374862)
		(width 0.1016)
		(layer "F.Cu")
		(net "M_A_CPU1_SA_DQ<24>")
	)
	(segment
		(start 66.36258 -287.84169)
		(end 66.237612 -287.84169)
		(width 0.20066)
		(layer "F.Cu")
		(net "M_A_CPU1_SA_DQ<24>")
	)
	(segment
		(start 56.37911 -287.826196)
		(end 56.44896 -287.826196)
		(width 0.101854)
		(layer "F.Cu")
		(net "M_A_CPU1_SA_DQ<24>")
	)
	(segment
		(start 76.460858 -284.341062)
		(end 72.919082 -287.882838)
		(width 0.20066)
		(layer "F.Cu")
		(net "M_A_CPU1_SA_DQ<24>")
	)
	(segment
		(start 56.464454 -287.84169)
		(end 58.669682 -287.84169)
		(width 0.1016)
		(layer "F.Cu")
		(net "M_A_CPU1_SA_DQ<24>")
	)
	(segment
		(start 72.919082 -287.882838)
		(end 67.521582 -287.882838)
		(width 0.20066)
		(layer "F.Cu")
		(net "M_A_CPU1_SA_DQ<24>")
	)
	(segment
		(start 67.521582 -287.882838)
		(end 67.34175 -288.06267)
		(width 0.20066)
		(layer "F.Cu")
		(net "M_A_CPU1_SA_DQ<24>")
	)
	(segment
		(start 64.12738 -287.84169)
		(end 64.10706 -287.82137)
		(width 0.101854)
		(layer "F.Cu")
		(net "M_A_CPU1_SA_DQ<24>")
	)
	(segment
		(start 67.34175 -288.06267)
		(end 66.58356 -288.06267)
		(width 0.20066)
		(layer "F.Cu")
		(net "M_A_CPU1_SA_DQ<24>")
	)
	(segment
		(start 76.865226 -281.90063)
		(end 76.865226 -283.936694)
		(width 0.1016)
		(layer "F.Cu")
		(net "M_A_CPU1_SA_DQ<24>")
	)
	(segment
		(start 54.66334 -288.518346)
		(end 54.897528 -288.284158)
		(width 0.20066)
		(layer "F.Cu")
		(net "M_A_CPU1_SA_DQ<24>")
	)
	(segment
		(start 54.897528 -287.996122)
		(end 55.067454 -287.826196)
		(width 0.20066)
		(layer "F.Cu")
		(net "M_A_CPU1_SA_DQ<24>")
	)
	(segment
		(start 77.76337 -277.386288)
		(end 76.865226 -281.90063)
		(width 0.1016)
		(layer "F.Cu")
		(net "M_A_CPU1_SA_DQ<24>")
	)
	(segment
		(start 66.58356 -288.06267)
		(end 66.36258 -287.84169)
		(width 0.20066)
		(layer "F.Cu")
		(net "M_A_CPU1_SA_DQ<24>")
	)
	(segment
		(start 55.067454 -287.826196)
		(end 56.37911 -287.826196)
		(width 0.20066)
		(layer "F.Cu")
		(net "M_A_CPU1_SA_DQ<24>")
	)
	(segment
		(start 64.10706 -287.82137)
		(end 63.951612 -287.82137)
		(width 0.101854)
		(layer "F.Cu")
		(net "M_A_CPU1_SA_DQ<24>")
	)
	(segment
		(start 59.523122 -288.266632)
		(end 60.947046 -288.266632)
		(width 0.20066)
		(layer "F.Cu")
		(net "M_A_CPU1_SA_DQ<24>")
	)
	(segment
		(start 54.027324 -288.266378)
		(end 54.279292 -288.518346)
		(width 0.20066)
		(layer "F.Cu")
		(net "M_A_CPU1_SA_DQ<24>")
	)
	(segment
		(start 58.669682 -287.84169)
		(end 58.684414 -287.826958)
		(width 0.101854)
		(layer "F.Cu")
		(net "M_A_CPU1_SA_DQ<24>")
	)
	(segment
		(start 66.352928 -289.532822)
		(end 66.040254 -289.532822)
		(width 0.20066)
		(layer "F.Cu")
		(net "M_A_CPU1_SA_DQ<23>")
	)
	(segment
		(start 74.086974 -287.972246)
		(end 74.086974 -288.256218)
		(width 0.20066)
		(layer "F.Cu")
		(net "M_A_CPU1_SA_DQ<23>")
	)
	(segment
		(start 85.30971 -270.018002)
		(end 84.898484 -270.429228)
		(width 0.088646)
		(layer "F.Cu")
		(net "M_A_CPU1_SA_DQ<23>")
	)
	(segment
		(start 59.188858 -289.116516)
		(end 59.314842 -289.2425)
		(width 0.20066)
		(layer "F.Cu")
		(net "M_A_CPU1_SA_DQ<23>")
	)
	(segment
		(start 62.775084 -288.95675)
		(end 63.251588 -288.95675)
		(width 0.20066)
		(layer "F.Cu")
		(net "M_A_CPU1_SA_DQ<23>")
	)
	(segment
		(start 59.822842 -289.554666)
		(end 59.861704 -289.554666)
		(width 0.101854)
		(layer "F.Cu")
		(net "M_A_CPU1_SA_DQ<23>")
	)
	(segment
		(start 78.356968 -277.542498)
		(end 77.578712 -281.44216)
		(width 0.1016)
		(layer "F.Cu")
		(net "M_A_CPU1_SA_DQ<23>")
	)
	(segment
		(start 86.845648 -270.079724)
		(end 86.76767 -270.001746)
		(width 0.088646)
		(layer "F.Cu")
		(net "M_A_CPU1_SA_DQ<23>")
	)
	(segment
		(start 76.72451 -286.870394)
		(end 76.72451 -287.154366)
		(width 0.20066)
		(layer "F.Cu")
		(net "M_A_CPU1_SA_DQ<23>")
	)
	(segment
		(start 86.257892 -270.30426)
		(end 86.257892 -270.095472)
		(width 0.088646)
		(layer "F.Cu")
		(net "M_A_CPU1_SA_DQ<23>")
	)
	(segment
		(start 75.092814 -286.966406)
		(end 75.092814 -287.250378)
		(width 0.20066)
		(layer "F.Cu")
		(net "M_A_CPU1_SA_DQ<23>")
	)
	(segment
		(start 76.72451 -287.154366)
		(end 76.505562 -287.373314)
		(width 0.20066)
		(layer "F.Cu")
		(net "M_A_CPU1_SA_DQ<23>")
	)
	(segment
		(start 84.671662 -270.429228)
		(end 84.45627 -270.64462)
		(width 0.088646)
		(layer "F.Cu")
		(net "M_A_CPU1_SA_DQ<23>")
	)
	(segment
		(start 84.092288 -271.008602)
		(end 79.277718 -275.82241)
		(width 0.1016)
		(layer "F.Cu")
		(net "M_A_CPU1_SA_DQ<23>")
	)
	(segment
		(start 86.845648 -270.475456)
		(end 86.845648 -270.079724)
		(width 0.088646)
		(layer "F.Cu")
		(net "M_A_CPU1_SA_DQ<23>")
	)
	(segment
		(start 63.251588 -288.95675)
		(end 63.411608 -289.11677)
		(width 0.20066)
		(layer "F.Cu")
		(net "M_A_CPU1_SA_DQ<23>")
	)
	(segment
		(start 76.597256 -285.702756)
		(end 76.356464 -285.702756)
		(width 0.20066)
		(layer "F.Cu")
		(net "M_A_CPU1_SA_DQ<23>")
	)
	(segment
		(start 59.314842 -289.40252)
		(end 59.466988 -289.554666)
		(width 0.20066)
		(layer "F.Cu")
		(net "M_A_CPU1_SA_DQ<23>")
	)
	(segment
		(start 84.898484 -270.429228)
		(end 84.671662 -270.429228)
		(width 0.088646)
		(layer "F.Cu")
		(net "M_A_CPU1_SA_DQ<23>")
	)
	(segment
		(start 86.54288 -270.092932)
		(end 86.54288 -270.273272)
		(width 0.088646)
		(layer "F.Cu")
		(net "M_A_CPU1_SA_DQ<23>")
	)
	(segment
		(start 85.725508 -269.862808)
		(end 85.570314 -270.018002)
		(width 0.088646)
		(layer "F.Cu")
		(net "M_A_CPU1_SA_DQ<23>")
	)
	(segment
		(start 86.458552 -270.3576)
		(end 86.311232 -270.3576)
		(width 0.088646)
		(layer "F.Cu")
		(net "M_A_CPU1_SA_DQ<23>")
	)
	(segment
		(start 76.098654 -286.244538)
		(end 76.72451 -286.870394)
		(width 0.20066)
		(layer "F.Cu")
		(net "M_A_CPU1_SA_DQ<23>")
	)
	(segment
		(start 77.47762 -285.840424)
		(end 77.236574 -286.08147)
		(width 0.20066)
		(layer "F.Cu")
		(net "M_A_CPU1_SA_DQ<23>")
	)
	(segment
		(start 74.589894 -287.753298)
		(end 74.305922 -287.753298)
		(width 0.20066)
		(layer "F.Cu")
		(net "M_A_CPU1_SA_DQ<23>")
	)
	(segment
		(start 86.257892 -270.095472)
		(end 86.025228 -269.862808)
		(width 0.088646)
		(layer "F.Cu")
		(net "M_A_CPU1_SA_DQ<23>")
	)
	(segment
		(start 67.897502 -288.771838)
		(end 67.574668 -289.094672)
		(width 0.20066)
		(layer "F.Cu")
		(net "M_A_CPU1_SA_DQ<23>")
	)
	(segment
		(start 76.098654 -285.960566)
		(end 76.098654 -286.244538)
		(width 0.20066)
		(layer "F.Cu")
		(net "M_A_CPU1_SA_DQ<23>")
	)
	(segment
		(start 74.20991 -289.384994)
		(end 73.596754 -288.771838)
		(width 0.20066)
		(layer "F.Cu")
		(net "M_A_CPU1_SA_DQ<23>")
	)
	(segment
		(start 62.430914 -289.541712)
		(end 62.57925 -289.393376)
		(width 0.20066)
		(layer "F.Cu")
		(net "M_A_CPU1_SA_DQ<23>")
	)
	(segment
		(start 86.025228 -269.862808)
		(end 85.725508 -269.862808)
		(width 0.088646)
		(layer "F.Cu")
		(net "M_A_CPU1_SA_DQ<23>")
	)
	(segment
		(start 59.861704 -289.554666)
		(end 59.874658 -289.541712)
		(width 0.101854)
		(layer "F.Cu")
		(net "M_A_CPU1_SA_DQ<23>")
	)
	(segment
		(start 57.503314 -289.11677)
		(end 59.188604 -289.11677)
		(width 0.20066)
		(layer "F.Cu")
		(net "M_A_CPU1_SA_DQ<23>")
	)
	(segment
		(start 77.236574 -286.08147)
		(end 76.97597 -286.08147)
		(width 0.20066)
		(layer "F.Cu")
		(net "M_A_CPU1_SA_DQ<23>")
	)
	(segment
		(start 84.45627 -270.64462)
		(end 84.092288 -271.008602)
		(width 0.1016)
		(layer "F.Cu")
		(net "M_A_CPU1_SA_DQ<23>")
	)
	(segment
		(start 62.57925 -289.152584)
		(end 62.775084 -288.95675)
		(width 0.20066)
		(layer "F.Cu")
		(net "M_A_CPU1_SA_DQ<23>")
	)
	(segment
		(start 66.040254 -289.532822)
		(end 65.623948 -289.116516)
		(width 0.20066)
		(layer "F.Cu")
		(net "M_A_CPU1_SA_DQ<23>")
	)
	(segment
		(start 59.874658 -289.541712)
		(end 62.097412 -289.541712)
		(width 0.1016)
		(layer "F.Cu")
		(net "M_A_CPU1_SA_DQ<23>")
	)
	(segment
		(start 77.578712 -281.44216)
		(end 77.578712 -285.739332)
		(width 0.1016)
		(layer "F.Cu")
		(net "M_A_CPU1_SA_DQ<23>")
	)
	(segment
		(start 86.311232 -270.3576)
		(end 86.257892 -270.30426)
		(width 0.088646)
		(layer "F.Cu")
		(net "M_A_CPU1_SA_DQ<23>")
	)
	(segment
		(start 79.277718 -275.82241)
		(end 78.356968 -277.542498)
		(width 0.1016)
		(layer "F.Cu")
		(net "M_A_CPU1_SA_DQ<23>")
	)
	(segment
		(start 77.578712 -285.739332)
		(end 77.47762 -285.840424)
		(width 0.1016)
		(layer "F.Cu")
		(net "M_A_CPU1_SA_DQ<23>")
	)
	(segment
		(start 76.22159 -287.373314)
		(end 75.595734 -286.747458)
		(width 0.20066)
		(layer "F.Cu")
		(net "M_A_CPU1_SA_DQ<23>")
	)
	(segment
		(start 75.71867 -287.876234)
		(end 75.71867 -288.160206)
		(width 0.20066)
		(layer "F.Cu")
		(net "M_A_CPU1_SA_DQ<23>")
	)
	(segment
		(start 76.505562 -287.373314)
		(end 76.22159 -287.373314)
		(width 0.20066)
		(layer "F.Cu")
		(net "M_A_CPU1_SA_DQ<23>")
	)
	(segment
		(start 62.57925 -289.393376)
		(end 62.57925 -289.152584)
		(width 0.20066)
		(layer "F.Cu")
		(net "M_A_CPU1_SA_DQ<23>")
	)
	(segment
		(start 75.092814 -287.250378)
		(end 75.71867 -287.876234)
		(width 0.20066)
		(layer "F.Cu")
		(net "M_A_CPU1_SA_DQ<23>")
	)
	(segment
		(start 59.466988 -289.554666)
		(end 59.822842 -289.554666)
		(width 0.20066)
		(layer "F.Cu")
		(net "M_A_CPU1_SA_DQ<23>")
	)
	(segment
		(start 75.71867 -288.160206)
		(end 75.499722 -288.379154)
		(width 0.20066)
		(layer "F.Cu")
		(net "M_A_CPU1_SA_DQ<23>")
	)
	(segment
		(start 76.356464 -285.702756)
		(end 76.098654 -285.960566)
		(width 0.20066)
		(layer "F.Cu")
		(net "M_A_CPU1_SA_DQ<23>")
	)
	(segment
		(start 67.574668 -289.094672)
		(end 66.791078 -289.094672)
		(width 0.20066)
		(layer "F.Cu")
		(net "M_A_CPU1_SA_DQ<23>")
	)
	(segment
		(start 75.499722 -288.379154)
		(end 75.21575 -288.379154)
		(width 0.20066)
		(layer "F.Cu")
		(net "M_A_CPU1_SA_DQ<23>")
	)
	(segment
		(start 74.086974 -288.256218)
		(end 74.71283 -288.882074)
		(width 0.20066)
		(layer "F.Cu")
		(net "M_A_CPU1_SA_DQ<23>")
	)
	(segment
		(start 75.21575 -288.379154)
		(end 74.589894 -287.753298)
		(width 0.20066)
		(layer "F.Cu")
		(net "M_A_CPU1_SA_DQ<23>")
	)
	(segment
		(start 76.97597 -286.08147)
		(end 76.597256 -285.702756)
		(width 0.20066)
		(layer "F.Cu")
		(net "M_A_CPU1_SA_DQ<23>")
	)
	(segment
		(start 74.71283 -289.166046)
		(end 74.493882 -289.384994)
		(width 0.20066)
		(layer "F.Cu")
		(net "M_A_CPU1_SA_DQ<23>")
	)
	(segment
		(start 75.311762 -286.747458)
		(end 75.092814 -286.966406)
		(width 0.20066)
		(layer "F.Cu")
		(net "M_A_CPU1_SA_DQ<23>")
	)
	(segment
		(start 63.411608 -289.11677)
		(end 65.047114 -289.11677)
		(width 0.20066)
		(layer "F.Cu")
		(net "M_A_CPU1_SA_DQ<23>")
	)
	(segment
		(start 65.623694 -289.11677)
		(end 65.047114 -289.11677)
		(width 0.20066)
		(layer "F.Cu")
		(net "M_A_CPU1_SA_DQ<23>")
	)
	(segment
		(start 75.595734 -286.747458)
		(end 75.311762 -286.747458)
		(width 0.20066)
		(layer "F.Cu")
		(net "M_A_CPU1_SA_DQ<23>")
	)
	(segment
		(start 59.188604 -289.11677)
		(end 59.188858 -289.116516)
		(width 0.20066)
		(layer "F.Cu")
		(net "M_A_CPU1_SA_DQ<23>")
	)
	(segment
		(start 65.623948 -289.116516)
		(end 65.623694 -289.11677)
		(width 0.20066)
		(layer "F.Cu")
		(net "M_A_CPU1_SA_DQ<23>")
	)
	(segment
		(start 74.493882 -289.384994)
		(end 74.20991 -289.384994)
		(width 0.20066)
		(layer "F.Cu")
		(net "M_A_CPU1_SA_DQ<23>")
	)
	(segment
		(start 86.54288 -270.273272)
		(end 86.458552 -270.3576)
		(width 0.088646)
		(layer "F.Cu")
		(net "M_A_CPU1_SA_DQ<23>")
	)
	(segment
		(start 86.76767 -270.001746)
		(end 86.634066 -270.001746)
		(width 0.088646)
		(layer "F.Cu")
		(net "M_A_CPU1_SA_DQ<23>")
	)
	(segment
		(start 74.71283 -288.882074)
		(end 74.71283 -289.166046)
		(width 0.20066)
		(layer "F.Cu")
		(net "M_A_CPU1_SA_DQ<23>")
	)
	(segment
		(start 74.305922 -287.753298)
		(end 74.086974 -287.972246)
		(width 0.20066)
		(layer "F.Cu")
		(net "M_A_CPU1_SA_DQ<23>")
	)
	(segment
		(start 62.147958 -289.541712)
		(end 62.430914 -289.541712)
		(width 0.20066)
		(layer "F.Cu")
		(net "M_A_CPU1_SA_DQ<23>")
	)
	(segment
		(start 66.791078 -289.094672)
		(end 66.352928 -289.532822)
		(width 0.20066)
		(layer "F.Cu")
		(net "M_A_CPU1_SA_DQ<23>")
	)
	(segment
		(start 62.097412 -289.541712)
		(end 62.147958 -289.541712)
		(width 0.101854)
		(layer "F.Cu")
		(net "M_A_CPU1_SA_DQ<23>")
	)
	(segment
		(start 59.314842 -289.2425)
		(end 59.314842 -289.40252)
		(width 0.20066)
		(layer "F.Cu")
		(net "M_A_CPU1_SA_DQ<23>")
	)
	(segment
		(start 73.596754 -288.771838)
		(end 67.897502 -288.771838)
		(width 0.20066)
		(layer "F.Cu")
		(net "M_A_CPU1_SA_DQ<23>")
	)
	(segment
		(start 86.634066 -270.001746)
		(end 86.54288 -270.092932)
		(width 0.088646)
		(layer "F.Cu")
		(net "M_A_CPU1_SA_DQ<23>")
	)
	(segment
		(start 85.570314 -270.018002)
		(end 85.30971 -270.018002)
		(width 0.088646)
		(layer "F.Cu")
		(net "M_A_CPU1_SA_DQ<23>")
	)
	(segment
		(start 87.241126 -270.735298)
		(end 87.12454 -270.735298)
		(width 0.088646)
		(layer "F.Cu")
		(net "M_A_CPU1_SA_DQ<22>")
	)
	(segment
		(start 75.937618 -290.6649)
		(end 74.40168 -290.6649)
		(width 0.20066)
		(layer "F.Cu")
		(net "M_A_CPU1_SA_DQ<22>")
	)
	(segment
		(start 78.93812 -277.750016)
		(end 78.188312 -281.503374)
		(width 0.1016)
		(layer "F.Cu")
		(net "M_A_CPU1_SA_DQ<22>")
	)
	(segment
		(start 78.188312 -281.503374)
		(end 78.188312 -287.818576)
		(width 0.1016)
		(layer "F.Cu")
		(net "M_A_CPU1_SA_DQ<22>")
	)
	(segment
		(start 59.102752 -290.71443)
		(end 59.102752 -290.506912)
		(width 0.20066)
		(layer "F.Cu")
		(net "M_A_CPU1_SA_DQ<22>")
	)
	(segment
		(start 70.64502 -290.86556)
		(end 70.44436 -290.6649)
		(width 0.20066)
		(layer "F.Cu")
		(net "M_A_CPU1_SA_DQ<22>")
	)
	(segment
		(start 87.315294 -270.809466)
		(end 87.241126 -270.735298)
		(width 0.088646)
		(layer "F.Cu")
		(net "M_A_CPU1_SA_DQ<22>")
	)
	(segment
		(start 86.599014 -270.98371)
		(end 86.599014 -270.76527)
		(width 0.088646)
		(layer "F.Cu")
		(net "M_A_CPU1_SA_DQ<22>")
	)
	(segment
		(start 86.898988 -271.12341)
		(end 86.738714 -271.12341)
		(width 0.088646)
		(layer "F.Cu")
		(net "M_A_CPU1_SA_DQ<22>")
	)
	(segment
		(start 78.00086 -288.601658)
		(end 75.937618 -290.6649)
		(width 0.20066)
		(layer "F.Cu")
		(net "M_A_CPU1_SA_DQ<22>")
	)
	(segment
		(start 86.059772 -271.074134)
		(end 85.980778 -271.153128)
		(width 0.088646)
		(layer "F.Cu")
		(net "M_A_CPU1_SA_DQ<22>")
	)
	(segment
		(start 59.238642 -290.371022)
		(end 59.822842 -290.371022)
		(width 0.20066)
		(layer "F.Cu")
		(net "M_A_CPU1_SA_DQ<22>")
	)
	(segment
		(start 72.06742 -291.35451)
		(end 72.06742 -290.86556)
		(width 0.20066)
		(layer "F.Cu")
		(net "M_A_CPU1_SA_DQ<22>")
	)
	(segment
		(start 85.794596 -271.153128)
		(end 85.583776 -270.942308)
		(width 0.088646)
		(layer "F.Cu")
		(net "M_A_CPU1_SA_DQ<22>")
	)
	(segment
		(start 74.00036 -291.55517)
		(end 73.69048 -291.55517)
		(width 0.20066)
		(layer "F.Cu")
		(net "M_A_CPU1_SA_DQ<22>")
	)
	(segment
		(start 59.822842 -290.371022)
		(end 59.8932 -290.371022)
		(width 0.101854)
		(layer "F.Cu")
		(net "M_A_CPU1_SA_DQ<22>")
	)
	(segment
		(start 87.315294 -271.289272)
		(end 87.315294 -270.809466)
		(width 0.088646)
		(layer "F.Cu")
		(net "M_A_CPU1_SA_DQ<22>")
	)
	(segment
		(start 72.26808 -291.55517)
		(end 72.06742 -291.35451)
		(width 0.20066)
		(layer "F.Cu")
		(net "M_A_CPU1_SA_DQ<22>")
	)
	(segment
		(start 73.48982 -291.35451)
		(end 73.48982 -290.86556)
		(width 0.20066)
		(layer "F.Cu")
		(net "M_A_CPU1_SA_DQ<22>")
	)
	(segment
		(start 70.64502 -291.35451)
		(end 70.64502 -290.86556)
		(width 0.20066)
		(layer "F.Cu")
		(net "M_A_CPU1_SA_DQ<22>")
	)
	(segment
		(start 59.8932 -290.371022)
		(end 59.913774 -290.391596)
		(width 0.101854)
		(layer "F.Cu")
		(net "M_A_CPU1_SA_DQ<22>")
	)
	(segment
		(start 59.00039 -290.816792)
		(end 59.102752 -290.71443)
		(width 0.20066)
		(layer "F.Cu")
		(net "M_A_CPU1_SA_DQ<22>")
	)
	(segment
		(start 85.042248 -271.083024)
		(end 84.880958 -271.083024)
		(width 0.088646)
		(layer "F.Cu")
		(net "M_A_CPU1_SA_DQ<22>")
	)
	(segment
		(start 86.599014 -270.76527)
		(end 86.500716 -270.666972)
		(width 0.088646)
		(layer "F.Cu")
		(net "M_A_CPU1_SA_DQ<22>")
	)
	(segment
		(start 87.005414 -271.016984)
		(end 86.898988 -271.12341)
		(width 0.088646)
		(layer "F.Cu")
		(net "M_A_CPU1_SA_DQ<22>")
	)
	(segment
		(start 71.55688 -290.6649)
		(end 71.35622 -290.86556)
		(width 0.20066)
		(layer "F.Cu")
		(net "M_A_CPU1_SA_DQ<22>")
	)
	(segment
		(start 59.102752 -290.506912)
		(end 59.238642 -290.371022)
		(width 0.20066)
		(layer "F.Cu")
		(net "M_A_CPU1_SA_DQ<22>")
	)
	(segment
		(start 63.080392 -290.816792)
		(end 65.047114 -290.816792)
		(width 0.20066)
		(layer "F.Cu")
		(net "M_A_CPU1_SA_DQ<22>")
	)
	(segment
		(start 65.941194 -290.816792)
		(end 65.047114 -290.816792)
		(width 0.20066)
		(layer "F.Cu")
		(net "M_A_CPU1_SA_DQ<22>")
	)
	(segment
		(start 66.770504 -290.915852)
		(end 66.040254 -290.915852)
		(width 0.20066)
		(layer "F.Cu")
		(net "M_A_CPU1_SA_DQ<22>")
	)
	(segment
		(start 62.51702 -290.532566)
		(end 62.51702 -290.772088)
		(width 0.20066)
		(layer "F.Cu")
		(net "M_A_CPU1_SA_DQ<22>")
	)
	(segment
		(start 72.57796 -291.55517)
		(end 72.26808 -291.55517)
		(width 0.20066)
		(layer "F.Cu")
		(net "M_A_CPU1_SA_DQ<22>")
	)
	(segment
		(start 72.97928 -290.6649)
		(end 72.77862 -290.86556)
		(width 0.20066)
		(layer "F.Cu")
		(net "M_A_CPU1_SA_DQ<22>")
	)
	(segment
		(start 85.483954 -270.55191)
		(end 85.337904 -270.55191)
		(width 0.088646)
		(layer "F.Cu")
		(net "M_A_CPU1_SA_DQ<22>")
	)
	(segment
		(start 71.86676 -290.6649)
		(end 71.55688 -290.6649)
		(width 0.20066)
		(layer "F.Cu")
		(net "M_A_CPU1_SA_DQ<22>")
	)
	(segment
		(start 84.12226 -271.841722)
		(end 79.772256 -276.19071)
		(width 0.1016)
		(layer "F.Cu")
		(net "M_A_CPU1_SA_DQ<22>")
	)
	(segment
		(start 78.00086 -288.166048)
		(end 78.00086 -288.601658)
		(width 0.20066)
		(layer "F.Cu")
		(net "M_A_CPU1_SA_DQ<22>")
	)
	(segment
		(start 59.913774 -290.391596)
		(end 62.136274 -290.391596)
		(width 0.1016)
		(layer "F.Cu")
		(net "M_A_CPU1_SA_DQ<22>")
	)
	(segment
		(start 67.021456 -290.6649)
		(end 66.770504 -290.915852)
		(width 0.20066)
		(layer "F.Cu")
		(net "M_A_CPU1_SA_DQ<22>")
	)
	(segment
		(start 86.235032 -270.722852)
		(end 86.059772 -271.074134)
		(width 0.088646)
		(layer "F.Cu")
		(net "M_A_CPU1_SA_DQ<22>")
	)
	(segment
		(start 78.00086 -288.006028)
		(end 78.00086 -288.166048)
		(width 0.1016)
		(layer "F.Cu")
		(net "M_A_CPU1_SA_DQ<22>")
	)
	(segment
		(start 63.080138 -290.816538)
		(end 63.080392 -290.816792)
		(width 0.20066)
		(layer "F.Cu")
		(net "M_A_CPU1_SA_DQ<22>")
	)
	(segment
		(start 57.503314 -290.816792)
		(end 59.00039 -290.816792)
		(width 0.20066)
		(layer "F.Cu")
		(net "M_A_CPU1_SA_DQ<22>")
	)
	(segment
		(start 71.35622 -291.35451)
		(end 71.15556 -291.55517)
		(width 0.20066)
		(layer "F.Cu")
		(net "M_A_CPU1_SA_DQ<22>")
	)
	(segment
		(start 62.147958 -290.391596)
		(end 62.37605 -290.391596)
		(width 0.20066)
		(layer "F.Cu")
		(net "M_A_CPU1_SA_DQ<22>")
	)
	(segment
		(start 79.772256 -276.19071)
		(end 78.93812 -277.750016)
		(width 0.1016)
		(layer "F.Cu")
		(net "M_A_CPU1_SA_DQ<22>")
	)
	(segment
		(start 86.290912 -270.666972)
		(end 86.235032 -270.722852)
		(width 0.088646)
		(layer "F.Cu")
		(net "M_A_CPU1_SA_DQ<22>")
	)
	(segment
		(start 84.880958 -271.083024)
		(end 84.354416 -271.609566)
		(width 0.088646)
		(layer "F.Cu")
		(net "M_A_CPU1_SA_DQ<22>")
	)
	(segment
		(start 84.354416 -271.609566)
		(end 84.12226 -271.841722)
		(width 0.1016)
		(layer "F.Cu")
		(net "M_A_CPU1_SA_DQ<22>")
	)
	(segment
		(start 72.06742 -290.86556)
		(end 71.86676 -290.6649)
		(width 0.20066)
		(layer "F.Cu")
		(net "M_A_CPU1_SA_DQ<22>")
	)
	(segment
		(start 74.40168 -290.6649)
		(end 74.20102 -290.86556)
		(width 0.20066)
		(layer "F.Cu")
		(net "M_A_CPU1_SA_DQ<22>")
	)
	(segment
		(start 87.005414 -270.854424)
		(end 87.005414 -271.016984)
		(width 0.088646)
		(layer "F.Cu")
		(net "M_A_CPU1_SA_DQ<22>")
	)
	(segment
		(start 74.20102 -290.86556)
		(end 74.20102 -291.35451)
		(width 0.20066)
		(layer "F.Cu")
		(net "M_A_CPU1_SA_DQ<22>")
	)
	(segment
		(start 70.84568 -291.55517)
		(end 70.64502 -291.35451)
		(width 0.20066)
		(layer "F.Cu")
		(net "M_A_CPU1_SA_DQ<22>")
	)
	(segment
		(start 72.77862 -290.86556)
		(end 72.77862 -291.35451)
		(width 0.20066)
		(layer "F.Cu")
		(net "M_A_CPU1_SA_DQ<22>")
	)
	(segment
		(start 70.44436 -290.6649)
		(end 67.021456 -290.6649)
		(width 0.20066)
		(layer "F.Cu")
		(net "M_A_CPU1_SA_DQ<22>")
	)
	(segment
		(start 86.738714 -271.12341)
		(end 86.599014 -270.98371)
		(width 0.088646)
		(layer "F.Cu")
		(net "M_A_CPU1_SA_DQ<22>")
	)
	(segment
		(start 62.51702 -290.772088)
		(end 62.689994 -290.945062)
		(width 0.20066)
		(layer "F.Cu")
		(net "M_A_CPU1_SA_DQ<22>")
	)
	(segment
		(start 62.136274 -290.391596)
		(end 62.147958 -290.391596)
		(width 0.101854)
		(layer "F.Cu")
		(net "M_A_CPU1_SA_DQ<22>")
	)
	(segment
		(start 66.040254 -290.915852)
		(end 65.941194 -290.816792)
		(width 0.20066)
		(layer "F.Cu")
		(net "M_A_CPU1_SA_DQ<22>")
	)
	(segment
		(start 74.20102 -291.35451)
		(end 74.00036 -291.55517)
		(width 0.20066)
		(layer "F.Cu")
		(net "M_A_CPU1_SA_DQ<22>")
	)
	(segment
		(start 85.980778 -271.153128)
		(end 85.794596 -271.153128)
		(width 0.088646)
		(layer "F.Cu")
		(net "M_A_CPU1_SA_DQ<22>")
	)
	(segment
		(start 85.583776 -270.942308)
		(end 85.583776 -270.651732)
		(width 0.088646)
		(layer "F.Cu")
		(net "M_A_CPU1_SA_DQ<22>")
	)
	(segment
		(start 85.13953 -270.985742)
		(end 85.042248 -271.083024)
		(width 0.088646)
		(layer "F.Cu")
		(net "M_A_CPU1_SA_DQ<22>")
	)
	(segment
		(start 62.37605 -290.391596)
		(end 62.51702 -290.532566)
		(width 0.20066)
		(layer "F.Cu")
		(net "M_A_CPU1_SA_DQ<22>")
	)
	(segment
		(start 78.188312 -287.818576)
		(end 78.00086 -288.006028)
		(width 0.1016)
		(layer "F.Cu")
		(net "M_A_CPU1_SA_DQ<22>")
	)
	(segment
		(start 85.583776 -270.651732)
		(end 85.483954 -270.55191)
		(width 0.088646)
		(layer "F.Cu")
		(net "M_A_CPU1_SA_DQ<22>")
	)
	(segment
		(start 73.28916 -290.6649)
		(end 72.97928 -290.6649)
		(width 0.20066)
		(layer "F.Cu")
		(net "M_A_CPU1_SA_DQ<22>")
	)
	(segment
		(start 85.337904 -270.55191)
		(end 85.13953 -270.750284)
		(width 0.088646)
		(layer "F.Cu")
		(net "M_A_CPU1_SA_DQ<22>")
	)
	(segment
		(start 62.951614 -290.945062)
		(end 63.080138 -290.816538)
		(width 0.20066)
		(layer "F.Cu")
		(net "M_A_CPU1_SA_DQ<22>")
	)
	(segment
		(start 85.13953 -270.750284)
		(end 85.13953 -270.985742)
		(width 0.088646)
		(layer "F.Cu")
		(net "M_A_CPU1_SA_DQ<22>")
	)
	(segment
		(start 72.77862 -291.35451)
		(end 72.57796 -291.55517)
		(width 0.20066)
		(layer "F.Cu")
		(net "M_A_CPU1_SA_DQ<22>")
	)
	(segment
		(start 71.15556 -291.55517)
		(end 70.84568 -291.55517)
		(width 0.20066)
		(layer "F.Cu")
		(net "M_A_CPU1_SA_DQ<22>")
	)
	(segment
		(start 73.69048 -291.55517)
		(end 73.48982 -291.35451)
		(width 0.20066)
		(layer "F.Cu")
		(net "M_A_CPU1_SA_DQ<22>")
	)
	(segment
		(start 73.48982 -290.86556)
		(end 73.28916 -290.6649)
		(width 0.20066)
		(layer "F.Cu")
		(net "M_A_CPU1_SA_DQ<22>")
	)
	(segment
		(start 71.35622 -290.86556)
		(end 71.35622 -291.35451)
		(width 0.20066)
		(layer "F.Cu")
		(net "M_A_CPU1_SA_DQ<22>")
	)
	(segment
		(start 86.500716 -270.666972)
		(end 86.290912 -270.666972)
		(width 0.088646)
		(layer "F.Cu")
		(net "M_A_CPU1_SA_DQ<22>")
	)
	(segment
		(start 87.12454 -270.735298)
		(end 87.005414 -270.854424)
		(width 0.088646)
		(layer "F.Cu")
		(net "M_A_CPU1_SA_DQ<22>")
	)
	(segment
		(start 62.689994 -290.945062)
		(end 62.951614 -290.945062)
		(width 0.20066)
		(layer "F.Cu")
		(net "M_A_CPU1_SA_DQ<22>")
	)
	(segment
		(start 66.703448 -290.025074)
		(end 66.331592 -290.39693)
		(width 0.20066)
		(layer "F.Cu")
		(net "M_A_CPU1_SA_DQ<21>")
	)
	(segment
		(start 54.897528 -289.696144)
		(end 55.069232 -289.52444)
		(width 0.20066)
		(layer "F.Cu")
		(net "M_A_CPU1_SA_DQ<21>")
	)
	(segment
		(start 77.179424 -288.185352)
		(end 77.179424 -288.469324)
		(width 0.20066)
		(layer "F.Cu")
		(net "M_A_CPU1_SA_DQ<21>")
	)
	(segment
		(start 69.03212 -290.025074)
		(end 68.83146 -289.824414)
		(width 0.20066)
		(layer "F.Cu")
		(net "M_A_CPU1_SA_DQ<21>")
	)
	(segment
		(start 77.7621 -286.807402)
		(end 77.7621 -286.845502)
		(width 0.101854)
		(layer "F.Cu")
		(net "M_A_CPU1_SA_DQ<21>")
	)
	(segment
		(start 77.730096 -286.855662)
		(end 77.491082 -287.094676)
		(width 0.20066)
		(layer "F.Cu")
		(net "M_A_CPU1_SA_DQ<21>")
	)
	(segment
		(start 77.75194 -286.855662)
		(end 77.730858 -286.855662)
		(width 0.101854)
		(layer "F.Cu")
		(net "M_A_CPU1_SA_DQ<21>")
	)
	(segment
		(start 68.12026 -289.685476)
		(end 68.12026 -289.824414)
		(width 0.20066)
		(layer "F.Cu")
		(net "M_A_CPU1_SA_DQ<21>")
	)
	(segment
		(start 59.274202 -289.966654)
		(end 60.947046 -289.966654)
		(width 0.20066)
		(layer "F.Cu")
		(net "M_A_CPU1_SA_DQ<21>")
	)
	(segment
		(start 79.525114 -276.006306)
		(end 78.64729 -277.646638)
		(width 0.1016)
		(layer "F.Cu")
		(net "M_A_CPU1_SA_DQ<21>")
	)
	(segment
		(start 75.24242 -289.54984)
		(end 74.767186 -290.025074)
		(width 0.20066)
		(layer "F.Cu")
		(net "M_A_CPU1_SA_DQ<21>")
	)
	(segment
		(start 70.25386 -289.824414)
		(end 70.25386 -289.685476)
		(width 0.20066)
		(layer "F.Cu")
		(net "M_A_CPU1_SA_DQ<21>")
	)
	(segment
		(start 64.146684 -290.405058)
		(end 63.977012 -290.405058)
		(width 0.101854)
		(layer "F.Cu")
		(net "M_A_CPU1_SA_DQ<21>")
	)
	(segment
		(start 84.63407 -270.89862)
		(end 84.633816 -270.89862)
		(width 0.088646)
		(layer "F.Cu")
		(net "M_A_CPU1_SA_DQ<21>")
	)
	(segment
		(start 77.7621 -286.845502)
		(end 77.75194 -286.855662)
		(width 0.101854)
		(layer "F.Cu")
		(net "M_A_CPU1_SA_DQ<21>")
	)
	(segment
		(start 66.186812 -290.39693)
		(end 65.916048 -290.39693)
		(width 0.101854)
		(layer "F.Cu")
		(net "M_A_CPU1_SA_DQ<21>")
	)
	(segment
		(start 54.027324 -289.9664)
		(end 54.279292 -290.218368)
		(width 0.20066)
		(layer "F.Cu")
		(net "M_A_CPU1_SA_DQ<21>")
	)
	(segment
		(start 56.37911 -289.52444)
		(end 56.430926 -289.52444)
		(width 0.101854)
		(layer "F.Cu")
		(net "M_A_CPU1_SA_DQ<21>")
	)
	(segment
		(start 67.9196 -290.025074)
		(end 66.703448 -290.025074)
		(width 0.20066)
		(layer "F.Cu")
		(net "M_A_CPU1_SA_DQ<21>")
	)
	(segment
		(start 76.029312 -289.04692)
		(end 76.173584 -289.191192)
		(width 0.20066)
		(layer "F.Cu")
		(net "M_A_CPU1_SA_DQ<21>")
	)
	(segment
		(start 62.64021 -289.966654)
		(end 60.947046 -289.966654)
		(width 0.20066)
		(layer "F.Cu")
		(net "M_A_CPU1_SA_DQ<21>")
	)
	(segment
		(start 84.633816 -270.89862)
		(end 84.262722 -271.269714)
		(width 0.1016)
		(layer "F.Cu")
		(net "M_A_CPU1_SA_DQ<21>")
	)
	(segment
		(start 70.45452 -290.025074)
		(end 70.25386 -289.824414)
		(width 0.20066)
		(layer "F.Cu")
		(net "M_A_CPU1_SA_DQ<21>")
	)
	(segment
		(start 54.66334 -290.218368)
		(end 54.897528 -289.98418)
		(width 0.20066)
		(layer "F.Cu")
		(net "M_A_CPU1_SA_DQ<21>")
	)
	(segment
		(start 68.83146 -289.824414)
		(end 68.83146 -289.685476)
		(width 0.20066)
		(layer "F.Cu")
		(net "M_A_CPU1_SA_DQ<21>")
	)
	(segment
		(start 69.342 -290.025074)
		(end 69.03212 -290.025074)
		(width 0.20066)
		(layer "F.Cu")
		(net "M_A_CPU1_SA_DQ<21>")
	)
	(segment
		(start 78.64729 -277.646638)
		(end 77.883512 -281.472386)
		(width 0.1016)
		(layer "F.Cu")
		(net "M_A_CPU1_SA_DQ<21>")
	)
	(segment
		(start 71.16572 -289.484816)
		(end 70.96506 -289.685476)
		(width 0.20066)
		(layer "F.Cu")
		(net "M_A_CPU1_SA_DQ<21>")
	)
	(segment
		(start 71.67626 -289.824414)
		(end 71.67626 -289.685476)
		(width 0.20066)
		(layer "F.Cu")
		(net "M_A_CPU1_SA_DQ<21>")
	)
	(segment
		(start 76.532232 -288.544)
		(end 76.24826 -288.544)
		(width 0.20066)
		(layer "F.Cu")
		(net "M_A_CPU1_SA_DQ<21>")
	)
	(segment
		(start 63.490856 -289.862768)
		(end 63.291974 -289.663886)
		(width 0.20066)
		(layer "F.Cu")
		(net "M_A_CPU1_SA_DQ<21>")
	)
	(segment
		(start 77.179424 -288.469324)
		(end 76.960476 -288.688272)
		(width 0.20066)
		(layer "F.Cu")
		(net "M_A_CPU1_SA_DQ<21>")
	)
	(segment
		(start 69.54266 -289.685476)
		(end 69.54266 -289.824414)
		(width 0.20066)
		(layer "F.Cu")
		(net "M_A_CPU1_SA_DQ<21>")
	)
	(segment
		(start 70.0532 -289.484816)
		(end 69.74332 -289.484816)
		(width 0.20066)
		(layer "F.Cu")
		(net "M_A_CPU1_SA_DQ<21>")
	)
	(segment
		(start 63.490856 -290.305998)
		(end 63.490856 -289.862768)
		(width 0.20066)
		(layer "F.Cu")
		(net "M_A_CPU1_SA_DQ<21>")
	)
	(segment
		(start 76.173584 -289.191192)
		(end 76.173584 -289.475164)
		(width 0.20066)
		(layer "F.Cu")
		(net "M_A_CPU1_SA_DQ<21>")
	)
	(segment
		(start 68.83146 -289.685476)
		(end 68.6308 -289.484816)
		(width 0.20066)
		(layer "F.Cu")
		(net "M_A_CPU1_SA_DQ<21>")
	)
	(segment
		(start 76.960476 -288.688272)
		(end 76.676504 -288.688272)
		(width 0.20066)
		(layer "F.Cu")
		(net "M_A_CPU1_SA_DQ<21>")
	)
	(segment
		(start 77.491082 -287.301178)
		(end 77.035152 -287.757108)
		(width 0.20066)
		(layer "F.Cu")
		(net "M_A_CPU1_SA_DQ<21>")
	)
	(segment
		(start 64.185292 -290.391596)
		(end 64.146684 -290.405058)
		(width 0.1016)
		(layer "F.Cu")
		(net "M_A_CPU1_SA_DQ<21>")
	)
	(segment
		(start 63.291974 -289.663886)
		(end 62.942978 -289.663886)
		(width 0.20066)
		(layer "F.Cu")
		(net "M_A_CPU1_SA_DQ<21>")
	)
	(segment
		(start 66.331592 -290.39693)
		(end 66.186812 -290.39693)
		(width 0.20066)
		(layer "F.Cu")
		(net "M_A_CPU1_SA_DQ<21>")
	)
	(segment
		(start 85.905594 -270.475456)
		(end 85.643212 -270.213074)
		(width 0.088646)
		(layer "F.Cu")
		(net "M_A_CPU1_SA_DQ<21>")
	)
	(segment
		(start 84.262722 -271.269714)
		(end 79.525114 -276.006306)
		(width 0.1016)
		(layer "F.Cu")
		(net "M_A_CPU1_SA_DQ<21>")
	)
	(segment
		(start 77.035152 -287.757108)
		(end 77.035152 -288.04108)
		(width 0.20066)
		(layer "F.Cu")
		(net "M_A_CPU1_SA_DQ<21>")
	)
	(segment
		(start 85.643212 -270.213074)
		(end 85.385402 -270.213074)
		(width 0.088646)
		(layer "F.Cu")
		(net "M_A_CPU1_SA_DQ<21>")
	)
	(segment
		(start 56.448198 -289.541712)
		(end 58.668412 -289.541712)
		(width 0.1016)
		(layer "F.Cu")
		(net "M_A_CPU1_SA_DQ<21>")
	)
	(segment
		(start 75.670664 -289.694112)
		(end 75.526392 -289.54984)
		(width 0.20066)
		(layer "F.Cu")
		(net "M_A_CPU1_SA_DQ<21>")
	)
	(segment
		(start 71.67626 -289.685476)
		(end 71.4756 -289.484816)
		(width 0.20066)
		(layer "F.Cu")
		(net "M_A_CPU1_SA_DQ<21>")
	)
	(segment
		(start 70.96506 -289.824414)
		(end 70.7644 -290.025074)
		(width 0.20066)
		(layer "F.Cu")
		(net "M_A_CPU1_SA_DQ<21>")
	)
	(segment
		(start 77.035152 -288.04108)
		(end 77.179424 -288.185352)
		(width 0.20066)
		(layer "F.Cu")
		(net "M_A_CPU1_SA_DQ<21>")
	)
	(segment
		(start 84.854034 -270.678656)
		(end 84.63407 -270.89862)
		(width 0.088646)
		(layer "F.Cu")
		(net "M_A_CPU1_SA_DQ<21>")
	)
	(segment
		(start 77.883512 -281.472386)
		(end 77.883512 -286.68599)
		(width 0.1016)
		(layer "F.Cu")
		(net "M_A_CPU1_SA_DQ<21>")
	)
	(segment
		(start 75.526392 -289.54984)
		(end 75.24242 -289.54984)
		(width 0.20066)
		(layer "F.Cu")
		(net "M_A_CPU1_SA_DQ<21>")
	)
	(segment
		(start 70.96506 -289.685476)
		(end 70.96506 -289.824414)
		(width 0.20066)
		(layer "F.Cu")
		(net "M_A_CPU1_SA_DQ<21>")
	)
	(segment
		(start 69.54266 -289.824414)
		(end 69.342 -290.025074)
		(width 0.20066)
		(layer "F.Cu")
		(net "M_A_CPU1_SA_DQ<21>")
	)
	(segment
		(start 54.279292 -290.218368)
		(end 54.66334 -290.218368)
		(width 0.20066)
		(layer "F.Cu")
		(net "M_A_CPU1_SA_DQ<21>")
	)
	(segment
		(start 85.385402 -270.213074)
		(end 84.91982 -270.678656)
		(width 0.088646)
		(layer "F.Cu")
		(net "M_A_CPU1_SA_DQ<21>")
	)
	(segment
		(start 77.491082 -287.094676)
		(end 77.491082 -287.301178)
		(width 0.20066)
		(layer "F.Cu")
		(net "M_A_CPU1_SA_DQ<21>")
	)
	(segment
		(start 62.942978 -289.663886)
		(end 62.64021 -289.966654)
		(width 0.20066)
		(layer "F.Cu")
		(net "M_A_CPU1_SA_DQ<21>")
	)
	(segment
		(start 77.730858 -286.855662)
		(end 77.730096 -286.855662)
		(width 0.20066)
		(layer "F.Cu")
		(net "M_A_CPU1_SA_DQ<21>")
	)
	(segment
		(start 68.32092 -289.484816)
		(end 68.12026 -289.685476)
		(width 0.20066)
		(layer "F.Cu")
		(net "M_A_CPU1_SA_DQ<21>")
	)
	(segment
		(start 56.430926 -289.52444)
		(end 56.448198 -289.541712)
		(width 0.101854)
		(layer "F.Cu")
		(net "M_A_CPU1_SA_DQ<21>")
	)
	(segment
		(start 76.676504 -288.688272)
		(end 76.532232 -288.544)
		(width 0.20066)
		(layer "F.Cu")
		(net "M_A_CPU1_SA_DQ<21>")
	)
	(segment
		(start 65.903348 -290.391596)
		(end 64.185292 -290.391596)
		(width 0.1016)
		(layer "F.Cu")
		(net "M_A_CPU1_SA_DQ<21>")
	)
	(segment
		(start 77.883512 -286.68599)
		(end 77.7621 -286.807402)
		(width 0.1016)
		(layer "F.Cu")
		(net "M_A_CPU1_SA_DQ<21>")
	)
	(segment
		(start 71.4756 -289.484816)
		(end 71.16572 -289.484816)
		(width 0.20066)
		(layer "F.Cu")
		(net "M_A_CPU1_SA_DQ<21>")
	)
	(segment
		(start 71.87692 -290.025074)
		(end 71.67626 -289.824414)
		(width 0.20066)
		(layer "F.Cu")
		(net "M_A_CPU1_SA_DQ<21>")
	)
	(segment
		(start 55.069232 -289.52444)
		(end 56.37911 -289.52444)
		(width 0.20066)
		(layer "F.Cu")
		(net "M_A_CPU1_SA_DQ<21>")
	)
	(segment
		(start 53.403246 -289.966654)
		(end 54.02707 -289.966654)
		(width 0.20066)
		(layer "F.Cu")
		(net "M_A_CPU1_SA_DQ<21>")
	)
	(segment
		(start 70.25386 -289.685476)
		(end 70.0532 -289.484816)
		(width 0.20066)
		(layer "F.Cu")
		(net "M_A_CPU1_SA_DQ<21>")
	)
	(segment
		(start 76.029312 -288.762948)
		(end 76.029312 -289.04692)
		(width 0.20066)
		(layer "F.Cu")
		(net "M_A_CPU1_SA_DQ<21>")
	)
	(segment
		(start 68.6308 -289.484816)
		(end 68.32092 -289.484816)
		(width 0.20066)
		(layer "F.Cu")
		(net "M_A_CPU1_SA_DQ<21>")
	)
	(segment
		(start 74.767186 -290.025074)
		(end 71.87692 -290.025074)
		(width 0.20066)
		(layer "F.Cu")
		(net "M_A_CPU1_SA_DQ<21>")
	)
	(segment
		(start 84.91982 -270.678656)
		(end 84.854034 -270.678656)
		(width 0.088646)
		(layer "F.Cu")
		(net "M_A_CPU1_SA_DQ<21>")
	)
	(segment
		(start 76.24826 -288.544)
		(end 76.029312 -288.762948)
		(width 0.20066)
		(layer "F.Cu")
		(net "M_A_CPU1_SA_DQ<21>")
	)
	(segment
		(start 68.12026 -289.824414)
		(end 67.9196 -290.025074)
		(width 0.20066)
		(layer "F.Cu")
		(net "M_A_CPU1_SA_DQ<21>")
	)
	(segment
		(start 54.02707 -289.966654)
		(end 54.027324 -289.9664)
		(width 0.20066)
		(layer "F.Cu")
		(net "M_A_CPU1_SA_DQ<21>")
	)
	(segment
		(start 70.7644 -290.025074)
		(end 70.45452 -290.025074)
		(width 0.20066)
		(layer "F.Cu")
		(net "M_A_CPU1_SA_DQ<21>")
	)
	(segment
		(start 69.74332 -289.484816)
		(end 69.54266 -289.685476)
		(width 0.20066)
		(layer "F.Cu")
		(net "M_A_CPU1_SA_DQ<21>")
	)
	(segment
		(start 76.173584 -289.475164)
		(end 75.954636 -289.694112)
		(width 0.20066)
		(layer "F.Cu")
		(net "M_A_CPU1_SA_DQ<21>")
	)
	(segment
		(start 75.954636 -289.694112)
		(end 75.670664 -289.694112)
		(width 0.20066)
		(layer "F.Cu")
		(net "M_A_CPU1_SA_DQ<21>")
	)
	(segment
		(start 58.668412 -289.541712)
		(end 58.704226 -289.541712)
		(width 0.101854)
		(layer "F.Cu")
		(net "M_A_CPU1_SA_DQ<21>")
	)
	(segment
		(start 58.84926 -289.541712)
		(end 59.274202 -289.966654)
		(width 0.20066)
		(layer "F.Cu")
		(net "M_A_CPU1_SA_DQ<21>")
	)
	(segment
		(start 63.589916 -290.405058)
		(end 63.490856 -290.305998)
		(width 0.20066)
		(layer "F.Cu")
		(net "M_A_CPU1_SA_DQ<21>")
	)
	(segment
		(start 63.977012 -290.405058)
		(end 63.589916 -290.405058)
		(width 0.20066)
		(layer "F.Cu")
		(net "M_A_CPU1_SA_DQ<21>")
	)
	(segment
		(start 58.704226 -289.541712)
		(end 58.84926 -289.541712)
		(width 0.20066)
		(layer "F.Cu")
		(net "M_A_CPU1_SA_DQ<21>")
	)
	(segment
		(start 54.897528 -289.98418)
		(end 54.897528 -289.696144)
		(width 0.20066)
		(layer "F.Cu")
		(net "M_A_CPU1_SA_DQ<21>")
	)
	(segment
		(start 65.916048 -290.39693)
		(end 65.903348 -290.391596)
		(width 0.1016)
		(layer "F.Cu")
		(net "M_A_CPU1_SA_DQ<21>")
	)
	(segment
		(start 60.085478 -291.666676)
		(end 60.947046 -291.666676)
		(width 0.20066)
		(layer "F.Cu")
		(net "M_A_CPU1_SA_DQ<20>")
	)
	(segment
		(start 75.861418 -291.729922)
		(end 78.391258 -289.200082)
		(width 0.20066)
		(layer "F.Cu")
		(net "M_A_CPU1_SA_DQ<20>")
	)
	(segment
		(start 63.951612 -292.125908)
		(end 63.998602 -292.125908)
		(width 0.101854)
		(layer "F.Cu")
		(net "M_A_CPU1_SA_DQ<20>")
	)
	(segment
		(start 66.009012 -292.102794)
		(end 66.384932 -292.102794)
		(width 0.20066)
		(layer "F.Cu")
		(net "M_A_CPU1_SA_DQ<20>")
	)
	(segment
		(start 67.39382 -291.549836)
		(end 67.59448 -291.349176)
		(width 0.20066)
		(layer "F.Cu")
		(net "M_A_CPU1_SA_DQ<20>")
	)
	(segment
		(start 78.391258 -289.200082)
		(end 78.493112 -289.098228)
		(width 0.1016)
		(layer "F.Cu")
		(net "M_A_CPU1_SA_DQ<20>")
	)
	(segment
		(start 67.39382 -292.045136)
		(end 67.39382 -291.549836)
		(width 0.20066)
		(layer "F.Cu")
		(net "M_A_CPU1_SA_DQ<20>")
	)
	(segment
		(start 68.10502 -291.549836)
		(end 68.10502 -292.045136)
		(width 0.20066)
		(layer "F.Cu")
		(net "M_A_CPU1_SA_DQ<20>")
	)
	(segment
		(start 65.984628 -292.091618)
		(end 65.995804 -292.102794)
		(width 0.101854)
		(layer "F.Cu")
		(net "M_A_CPU1_SA_DQ<20>")
	)
	(segment
		(start 55.373524 -291.918644)
		(end 55.607712 -291.684456)
		(width 0.20066)
		(layer "F.Cu")
		(net "M_A_CPU1_SA_DQ<20>")
	)
	(segment
		(start 58.704226 -291.231066)
		(end 59.067446 -291.231066)
		(width 0.20066)
		(layer "F.Cu")
		(net "M_A_CPU1_SA_DQ<20>")
	)
	(segment
		(start 84.934806 -271.635728)
		(end 85.014562 -271.555972)
		(width 0.088646)
		(layer "F.Cu")
		(net "M_A_CPU1_SA_DQ<20>")
	)
	(segment
		(start 59.355736 -291.519356)
		(end 59.938158 -291.519356)
		(width 0.20066)
		(layer "F.Cu")
		(net "M_A_CPU1_SA_DQ<20>")
	)
	(segment
		(start 55.787798 -291.216334)
		(end 56.37911 -291.216334)
		(width 0.20066)
		(layer "F.Cu")
		(net "M_A_CPU1_SA_DQ<20>")
	)
	(segment
		(start 66.527934 -292.245796)
		(end 67.19316 -292.245796)
		(width 0.20066)
		(layer "F.Cu")
		(net "M_A_CPU1_SA_DQ<20>")
	)
	(segment
		(start 53.403246 -291.666676)
		(end 54.737508 -291.666676)
		(width 0.20066)
		(layer "F.Cu")
		(net "M_A_CPU1_SA_DQ<20>")
	)
	(segment
		(start 83.32216 -273.074384)
		(end 84.760816 -271.635728)
		(width 0.088646)
		(layer "F.Cu")
		(net "M_A_CPU1_SA_DQ<20>")
	)
	(segment
		(start 79.228188 -277.85441)
		(end 80.018636 -276.377146)
		(width 0.1016)
		(layer "F.Cu")
		(net "M_A_CPU1_SA_DQ<20>")
	)
	(segment
		(start 67.19316 -292.245796)
		(end 67.39382 -292.045136)
		(width 0.20066)
		(layer "F.Cu")
		(net "M_A_CPU1_SA_DQ<20>")
	)
	(segment
		(start 85.014562 -271.380458)
		(end 85.105748 -271.289272)
		(width 0.088646)
		(layer "F.Cu")
		(net "M_A_CPU1_SA_DQ<20>")
	)
	(segment
		(start 74.616056 -292.245796)
		(end 75.861418 -291.729922)
		(width 0.20066)
		(layer "F.Cu")
		(net "M_A_CPU1_SA_DQ<20>")
	)
	(segment
		(start 62.512702 -291.666676)
		(end 63.620396 -292.125908)
		(width 0.20066)
		(layer "F.Cu")
		(net "M_A_CPU1_SA_DQ<20>")
	)
	(segment
		(start 59.067446 -291.231066)
		(end 59.355736 -291.519356)
		(width 0.20066)
		(layer "F.Cu")
		(net "M_A_CPU1_SA_DQ<20>")
	)
	(segment
		(start 67.90436 -291.349176)
		(end 68.10502 -291.549836)
		(width 0.20066)
		(layer "F.Cu")
		(net "M_A_CPU1_SA_DQ<20>")
	)
	(segment
		(start 58.634122 -291.241734)
		(end 58.64479 -291.231066)
		(width 0.101854)
		(layer "F.Cu")
		(net "M_A_CPU1_SA_DQ<20>")
	)
	(segment
		(start 63.998602 -292.125908)
		(end 64.032892 -292.091618)
		(width 0.101854)
		(layer "F.Cu")
		(net "M_A_CPU1_SA_DQ<20>")
	)
	(segment
		(start 67.59448 -291.349176)
		(end 67.90436 -291.349176)
		(width 0.20066)
		(layer "F.Cu")
		(net "M_A_CPU1_SA_DQ<20>")
	)
	(segment
		(start 60.947046 -291.666676)
		(end 62.512702 -291.666676)
		(width 0.20066)
		(layer "F.Cu")
		(net "M_A_CPU1_SA_DQ<20>")
	)
	(segment
		(start 68.30568 -292.245796)
		(end 68.61556 -292.245796)
		(width 0.20066)
		(layer "F.Cu")
		(net "M_A_CPU1_SA_DQ<20>")
	)
	(segment
		(start 78.493112 -281.534108)
		(end 79.228188 -277.85441)
		(width 0.1016)
		(layer "F.Cu")
		(net "M_A_CPU1_SA_DQ<20>")
	)
	(segment
		(start 69.72808 -292.245796)
		(end 74.616056 -292.245796)
		(width 0.20066)
		(layer "F.Cu")
		(net "M_A_CPU1_SA_DQ<20>")
	)
	(segment
		(start 63.620396 -292.125908)
		(end 63.951612 -292.125908)
		(width 0.20066)
		(layer "F.Cu")
		(net "M_A_CPU1_SA_DQ<20>")
	)
	(segment
		(start 66.384932 -292.102794)
		(end 66.527934 -292.245796)
		(width 0.20066)
		(layer "F.Cu")
		(net "M_A_CPU1_SA_DQ<20>")
	)
	(segment
		(start 68.81622 -291.549836)
		(end 69.01688 -291.349176)
		(width 0.20066)
		(layer "F.Cu")
		(net "M_A_CPU1_SA_DQ<20>")
	)
	(segment
		(start 54.989476 -291.918644)
		(end 55.373524 -291.918644)
		(width 0.20066)
		(layer "F.Cu")
		(net "M_A_CPU1_SA_DQ<20>")
	)
	(segment
		(start 83.31708 -273.07921)
		(end 83.32216 -273.074384)
		(width 0.088646)
		(layer "F.Cu")
		(net "M_A_CPU1_SA_DQ<20>")
	)
	(segment
		(start 54.737508 -291.666676)
		(end 54.989476 -291.918644)
		(width 0.20066)
		(layer "F.Cu")
		(net "M_A_CPU1_SA_DQ<20>")
	)
	(segment
		(start 65.995804 -292.102794)
		(end 66.009012 -292.102794)
		(width 0.101854)
		(layer "F.Cu")
		(net "M_A_CPU1_SA_DQ<20>")
	)
	(segment
		(start 64.032892 -292.091618)
		(end 65.984628 -292.091618)
		(width 0.1016)
		(layer "F.Cu")
		(net "M_A_CPU1_SA_DQ<20>")
	)
	(segment
		(start 56.37911 -291.216334)
		(end 56.43753 -291.216334)
		(width 0.101854)
		(layer "F.Cu")
		(net "M_A_CPU1_SA_DQ<20>")
	)
	(segment
		(start 68.81622 -292.045136)
		(end 68.81622 -291.549836)
		(width 0.20066)
		(layer "F.Cu")
		(net "M_A_CPU1_SA_DQ<20>")
	)
	(segment
		(start 58.64479 -291.231066)
		(end 58.704226 -291.231066)
		(width 0.101854)
		(layer "F.Cu")
		(net "M_A_CPU1_SA_DQ<20>")
	)
	(segment
		(start 69.01688 -291.349176)
		(end 69.32676 -291.349176)
		(width 0.20066)
		(layer "F.Cu")
		(net "M_A_CPU1_SA_DQ<20>")
	)
	(segment
		(start 69.32676 -291.349176)
		(end 69.52742 -291.549836)
		(width 0.20066)
		(layer "F.Cu")
		(net "M_A_CPU1_SA_DQ<20>")
	)
	(segment
		(start 55.607712 -291.39642)
		(end 55.787798 -291.216334)
		(width 0.20066)
		(layer "F.Cu")
		(net "M_A_CPU1_SA_DQ<20>")
	)
	(segment
		(start 85.014562 -271.555972)
		(end 85.014562 -271.380458)
		(width 0.088646)
		(layer "F.Cu")
		(net "M_A_CPU1_SA_DQ<20>")
	)
	(segment
		(start 68.10502 -292.045136)
		(end 68.30568 -292.245796)
		(width 0.20066)
		(layer "F.Cu")
		(net "M_A_CPU1_SA_DQ<20>")
	)
	(segment
		(start 78.493112 -289.098228)
		(end 78.493112 -281.534108)
		(width 0.1016)
		(layer "F.Cu")
		(net "M_A_CPU1_SA_DQ<20>")
	)
	(segment
		(start 84.760816 -271.635728)
		(end 84.934806 -271.635728)
		(width 0.088646)
		(layer "F.Cu")
		(net "M_A_CPU1_SA_DQ<20>")
	)
	(segment
		(start 59.938158 -291.519356)
		(end 60.085478 -291.666676)
		(width 0.20066)
		(layer "F.Cu")
		(net "M_A_CPU1_SA_DQ<20>")
	)
	(segment
		(start 85.105748 -271.289272)
		(end 85.435694 -271.289272)
		(width 0.088646)
		(layer "F.Cu")
		(net "M_A_CPU1_SA_DQ<20>")
	)
	(segment
		(start 56.46293 -291.241734)
		(end 58.634122 -291.241734)
		(width 0.1016)
		(layer "F.Cu")
		(net "M_A_CPU1_SA_DQ<20>")
	)
	(segment
		(start 56.43753 -291.216334)
		(end 56.46293 -291.241734)
		(width 0.101854)
		(layer "F.Cu")
		(net "M_A_CPU1_SA_DQ<20>")
	)
	(segment
		(start 83.300316 -273.09572)
		(end 83.31708 -273.07921)
		(width 0.088646)
		(layer "F.Cu")
		(net "M_A_CPU1_SA_DQ<20>")
	)
	(segment
		(start 69.52742 -292.045136)
		(end 69.72808 -292.245796)
		(width 0.20066)
		(layer "F.Cu")
		(net "M_A_CPU1_SA_DQ<20>")
	)
	(segment
		(start 80.018636 -276.377146)
		(end 83.300316 -273.09572)
		(width 0.1016)
		(layer "F.Cu")
		(net "M_A_CPU1_SA_DQ<20>")
	)
	(segment
		(start 69.52742 -291.549836)
		(end 69.52742 -292.045136)
		(width 0.20066)
		(layer "F.Cu")
		(net "M_A_CPU1_SA_DQ<20>")
	)
	(segment
		(start 55.607712 -291.684456)
		(end 55.607712 -291.39642)
		(width 0.20066)
		(layer "F.Cu")
		(net "M_A_CPU1_SA_DQ<20>")
	)
	(segment
		(start 68.61556 -292.245796)
		(end 68.81622 -292.045136)
		(width 0.20066)
		(layer "F.Cu")
		(net "M_A_CPU1_SA_DQ<20>")
	)
	(segment
		(start 54.027324 -314.616338)
		(end 54.279292 -314.868306)
		(width 0.20066)
		(layer "F.Cu")
		(net "M_A_CPU1_SA_DQ<1>")
	)
	(segment
		(start 83.777582 -298.455842)
		(end 83.654138 -298.529502)
		(width 0.1016)
		(layer "F.Cu")
		(net "M_A_CPU1_SA_DQ<1>")
	)
	(segment
		(start 68.597272 -313.88431)
		(end 67.097656 -314.505594)
		(width 0.20066)
		(layer "F.Cu")
		(net "M_A_CPU1_SA_DQ<1>")
	)
	(segment
		(start 58.704226 -314.185554)
		(end 59.01055 -314.185554)
		(width 0.20066)
		(layer "F.Cu")
		(net "M_A_CPU1_SA_DQ<1>")
	)
	(segment
		(start 83.949032 -297.894756)
		(end 84.09813 -298.144692)
		(width 0.1016)
		(layer "F.Cu")
		(net "M_A_CPU1_SA_DQ<1>")
	)
	(segment
		(start 63.411354 -315.051694)
		(end 63.251334 -314.891674)
		(width 0.20066)
		(layer "F.Cu")
		(net "M_A_CPU1_SA_DQ<1>")
	)
	(segment
		(start 56.396636 -314.17514)
		(end 56.413146 -314.19165)
		(width 0.101854)
		(layer "F.Cu")
		(net "M_A_CPU1_SA_DQ<1>")
	)
	(segment
		(start 84.572094 -280.792428)
		(end 84.233512 -282.486354)
		(width 0.1016)
		(layer "F.Cu")
		(net "M_A_CPU1_SA_DQ<1>")
	)
	(segment
		(start 66.690494 -314.505594)
		(end 66.583814 -314.612274)
		(width 0.20066)
		(layer "F.Cu")
		(net "M_A_CPU1_SA_DQ<1>")
	)
	(segment
		(start 56.413146 -314.19165)
		(end 58.643012 -314.19165)
		(width 0.1016)
		(layer "F.Cu")
		(net "M_A_CPU1_SA_DQ<1>")
	)
	(segment
		(start 53.403246 -314.616592)
		(end 54.02707 -314.616592)
		(width 0.20066)
		(layer "F.Cu")
		(net "M_A_CPU1_SA_DQ<1>")
	)
	(segment
		(start 59.441588 -314.616592)
		(end 60.947046 -314.616592)
		(width 0.20066)
		(layer "F.Cu")
		(net "M_A_CPU1_SA_DQ<1>")
	)
	(segment
		(start 54.66334 -314.868306)
		(end 54.897528 -314.634118)
		(width 0.20066)
		(layer "F.Cu")
		(net "M_A_CPU1_SA_DQ<1>")
	)
	(segment
		(start 83.615784 -298.683934)
		(end 83.7946 -298.981622)
		(width 0.1016)
		(layer "F.Cu")
		(net "M_A_CPU1_SA_DQ<1>")
	)
	(segment
		(start 56.37911 -314.17514)
		(end 56.396636 -314.17514)
		(width 0.101854)
		(layer "F.Cu")
		(net "M_A_CPU1_SA_DQ<1>")
	)
	(segment
		(start 69.8627 -313.038744)
		(end 68.597272 -313.88431)
		(width 0.20066)
		(layer "F.Cu")
		(net "M_A_CPU1_SA_DQ<1>")
	)
	(segment
		(start 62.831472 -314.466732)
		(end 62.681612 -314.616592)
		(width 0.20066)
		(layer "F.Cu")
		(net "M_A_CPU1_SA_DQ<1>")
	)
	(segment
		(start 66.583814 -314.851288)
		(end 66.382392 -315.05271)
		(width 0.20066)
		(layer "F.Cu")
		(net "M_A_CPU1_SA_DQ<1>")
	)
	(segment
		(start 58.649108 -314.185554)
		(end 58.704226 -314.185554)
		(width 0.101854)
		(layer "F.Cu")
		(net "M_A_CPU1_SA_DQ<1>")
	)
	(segment
		(start 66.161412 -315.05271)
		(end 66.122804 -315.05271)
		(width 0.101854)
		(layer "F.Cu")
		(net "M_A_CPU1_SA_DQ<1>")
	)
	(segment
		(start 54.279292 -314.868306)
		(end 54.66334 -314.868306)
		(width 0.20066)
		(layer "F.Cu")
		(net "M_A_CPU1_SA_DQ<1>")
	)
	(segment
		(start 54.897528 -314.346082)
		(end 55.06847 -314.17514)
		(width 0.20066)
		(layer "F.Cu")
		(net "M_A_CPU1_SA_DQ<1>")
	)
	(segment
		(start 83.650074 -299.25137)
		(end 69.8627 -313.038744)
		(width 0.20066)
		(layer "F.Cu")
		(net "M_A_CPU1_SA_DQ<1>")
	)
	(segment
		(start 66.111628 -315.041534)
		(end 64.044068 -315.041534)
		(width 0.1016)
		(layer "F.Cu")
		(net "M_A_CPU1_SA_DQ<1>")
	)
	(segment
		(start 66.583814 -314.612274)
		(end 66.583814 -314.851288)
		(width 0.20066)
		(layer "F.Cu")
		(net "M_A_CPU1_SA_DQ<1>")
	)
	(segment
		(start 85.212428 -279.84196)
		(end 84.987384 -279.84196)
		(width 0.1016)
		(layer "F.Cu")
		(net "M_A_CPU1_SA_DQ<1>")
	)
	(segment
		(start 83.654138 -298.529502)
		(end 83.615784 -298.683934)
		(width 0.1016)
		(layer "F.Cu")
		(net "M_A_CPU1_SA_DQ<1>")
	)
	(segment
		(start 85.29193 -279.571958)
		(end 85.29193 -279.762458)
		(width 0.088646)
		(layer "F.Cu")
		(net "M_A_CPU1_SA_DQ<1>")
	)
	(segment
		(start 66.122804 -315.05271)
		(end 66.111628 -315.041534)
		(width 0.101854)
		(layer "F.Cu")
		(net "M_A_CPU1_SA_DQ<1>")
	)
	(segment
		(start 84.233512 -297.239182)
		(end 84.15528 -297.551348)
		(width 0.1016)
		(layer "F.Cu")
		(net "M_A_CPU1_SA_DQ<1>")
	)
	(segment
		(start 84.987384 -279.84196)
		(end 84.705952 -280.123392)
		(width 0.1016)
		(layer "F.Cu")
		(net "M_A_CPU1_SA_DQ<1>")
	)
	(segment
		(start 83.7946 -298.981622)
		(end 83.777074 -299.12437)
		(width 0.1016)
		(layer "F.Cu")
		(net "M_A_CPU1_SA_DQ<1>")
	)
	(segment
		(start 84.676488 -280.270966)
		(end 84.781898 -280.429208)
		(width 0.1016)
		(layer "F.Cu")
		(net "M_A_CPU1_SA_DQ<1>")
	)
	(segment
		(start 84.03082 -298.414186)
		(end 83.90636 -298.488354)
		(width 0.1016)
		(layer "F.Cu")
		(net "M_A_CPU1_SA_DQ<1>")
	)
	(segment
		(start 63.251334 -314.891674)
		(end 63.251334 -314.623958)
		(width 0.20066)
		(layer "F.Cu")
		(net "M_A_CPU1_SA_DQ<1>")
	)
	(segment
		(start 64.044068 -315.041534)
		(end 64.033908 -315.051694)
		(width 0.101854)
		(layer "F.Cu")
		(net "M_A_CPU1_SA_DQ<1>")
	)
	(segment
		(start 58.643012 -314.19165)
		(end 58.649108 -314.185554)
		(width 0.101854)
		(layer "F.Cu")
		(net "M_A_CPU1_SA_DQ<1>")
	)
	(segment
		(start 84.09813 -298.144692)
		(end 84.03082 -298.414186)
		(width 0.1016)
		(layer "F.Cu")
		(net "M_A_CPU1_SA_DQ<1>")
	)
	(segment
		(start 59.01055 -314.185554)
		(end 59.441588 -314.616592)
		(width 0.20066)
		(layer "F.Cu")
		(net "M_A_CPU1_SA_DQ<1>")
	)
	(segment
		(start 55.06847 -314.17514)
		(end 56.37911 -314.17514)
		(width 0.20066)
		(layer "F.Cu")
		(net "M_A_CPU1_SA_DQ<1>")
	)
	(segment
		(start 84.705952 -280.123392)
		(end 84.676488 -280.270966)
		(width 0.1016)
		(layer "F.Cu")
		(net "M_A_CPU1_SA_DQ<1>")
	)
	(segment
		(start 64.033908 -315.051694)
		(end 64.002412 -315.051694)
		(width 0.101854)
		(layer "F.Cu")
		(net "M_A_CPU1_SA_DQ<1>")
	)
	(segment
		(start 54.897528 -314.634118)
		(end 54.897528 -314.346082)
		(width 0.20066)
		(layer "F.Cu")
		(net "M_A_CPU1_SA_DQ<1>")
	)
	(segment
		(start 62.681612 -314.616592)
		(end 60.947046 -314.616592)
		(width 0.20066)
		(layer "F.Cu")
		(net "M_A_CPU1_SA_DQ<1>")
	)
	(segment
		(start 84.730336 -280.687018)
		(end 84.572094 -280.792428)
		(width 0.1016)
		(layer "F.Cu")
		(net "M_A_CPU1_SA_DQ<1>")
	)
	(segment
		(start 84.233512 -282.486354)
		(end 84.233512 -297.239182)
		(width 0.1016)
		(layer "F.Cu")
		(net "M_A_CPU1_SA_DQ<1>")
	)
	(segment
		(start 63.251334 -314.623958)
		(end 63.094108 -314.466732)
		(width 0.20066)
		(layer "F.Cu")
		(net "M_A_CPU1_SA_DQ<1>")
	)
	(segment
		(start 83.777074 -299.12437)
		(end 83.650074 -299.25137)
		(width 0.1016)
		(layer "F.Cu")
		(net "M_A_CPU1_SA_DQ<1>")
	)
	(segment
		(start 66.382392 -315.05271)
		(end 66.161412 -315.05271)
		(width 0.20066)
		(layer "F.Cu")
		(net "M_A_CPU1_SA_DQ<1>")
	)
	(segment
		(start 63.094108 -314.466732)
		(end 62.831472 -314.466732)
		(width 0.20066)
		(layer "F.Cu")
		(net "M_A_CPU1_SA_DQ<1>")
	)
	(segment
		(start 84.013548 -297.63593)
		(end 83.949032 -297.894756)
		(width 0.1016)
		(layer "F.Cu")
		(net "M_A_CPU1_SA_DQ<1>")
	)
	(segment
		(start 54.02707 -314.616592)
		(end 54.027324 -314.616338)
		(width 0.20066)
		(layer "F.Cu")
		(net "M_A_CPU1_SA_DQ<1>")
	)
	(segment
		(start 84.15528 -297.551348)
		(end 84.013548 -297.63593)
		(width 0.1016)
		(layer "F.Cu")
		(net "M_A_CPU1_SA_DQ<1>")
	)
	(segment
		(start 85.435694 -279.428194)
		(end 85.29193 -279.571958)
		(width 0.088646)
		(layer "F.Cu")
		(net "M_A_CPU1_SA_DQ<1>")
	)
	(segment
		(start 83.90636 -298.488354)
		(end 83.777582 -298.455842)
		(width 0.1016)
		(layer "F.Cu")
		(net "M_A_CPU1_SA_DQ<1>")
	)
	(segment
		(start 67.097656 -314.505594)
		(end 66.690494 -314.505594)
		(width 0.20066)
		(layer "F.Cu")
		(net "M_A_CPU1_SA_DQ<1>")
	)
	(segment
		(start 85.29193 -279.762458)
		(end 85.212428 -279.84196)
		(width 0.1016)
		(layer "F.Cu")
		(net "M_A_CPU1_SA_DQ<1>")
	)
	(segment
		(start 64.002412 -315.051694)
		(end 63.411354 -315.051694)
		(width 0.20066)
		(layer "F.Cu")
		(net "M_A_CPU1_SA_DQ<1>")
	)
	(segment
		(start 84.781898 -280.429208)
		(end 84.730336 -280.687018)
		(width 0.1016)
		(layer "F.Cu")
		(net "M_A_CPU1_SA_DQ<1>")
	)
	(segment
		(start 85.56244 -273.472656)
		(end 85.162644 -273.472656)
		(width 0.088646)
		(layer "F.Cu")
		(net "M_A_CPU1_SA_DQ<19>")
	)
	(segment
		(start 84.422488 -273.81581)
		(end 84.422488 -274.131024)
		(width 0.088646)
		(layer "F.Cu")
		(net "M_A_CPU1_SA_DQ<19>")
	)
	(segment
		(start 72.405748 -295.304464)
		(end 72.095868 -295.304464)
		(width 0.20066)
		(layer "F.Cu")
		(net "M_A_CPU1_SA_DQ<19>")
	)
	(segment
		(start 68.138548 -295.304464)
		(end 66.386202 -295.304464)
		(width 0.20066)
		(layer "F.Cu")
		(net "M_A_CPU1_SA_DQ<19>")
	)
	(segment
		(start 72.807068 -295.883584)
		(end 72.606408 -295.682924)
		(width 0.20066)
		(layer "F.Cu")
		(net "M_A_CPU1_SA_DQ<19>")
	)
	(segment
		(start 72.095868 -295.304464)
		(end 71.895208 -295.505124)
		(width 0.20066)
		(layer "F.Cu")
		(net "M_A_CPU1_SA_DQ<19>")
	)
	(segment
		(start 59.822842 -295.507156)
		(end 59.846718 -295.507156)
		(width 0.101854)
		(layer "F.Cu")
		(net "M_A_CPU1_SA_DQ<19>")
	)
	(segment
		(start 69.050408 -295.682924)
		(end 68.849748 -295.883584)
		(width 0.20066)
		(layer "F.Cu")
		(net "M_A_CPU1_SA_DQ<19>")
	)
	(segment
		(start 70.472808 -295.682924)
		(end 70.272148 -295.883584)
		(width 0.20066)
		(layer "F.Cu")
		(net "M_A_CPU1_SA_DQ<19>")
	)
	(segment
		(start 83.947254 -274.606258)
		(end 81.259172 -277.29434)
		(width 0.1016)
		(layer "F.Cu")
		(net "M_A_CPU1_SA_DQ<19>")
	)
	(segment
		(start 63.518796 -295.491662)
		(end 63.794132 -295.491662)
		(width 0.20066)
		(layer "F.Cu")
		(net "M_A_CPU1_SA_DQ<19>")
	)
	(segment
		(start 77.464412 -294.191944)
		(end 74.77887 -295.304464)
		(width 0.20066)
		(layer "F.Cu")
		(net "M_A_CPU1_SA_DQ<19>")
	)
	(segment
		(start 70.983348 -295.304464)
		(end 70.673468 -295.304464)
		(width 0.20066)
		(layer "F.Cu")
		(net "M_A_CPU1_SA_DQ<19>")
	)
	(segment
		(start 62.40907 -295.491662)
		(end 62.758828 -295.141904)
		(width 0.20066)
		(layer "F.Cu")
		(net "M_A_CPU1_SA_DQ<19>")
	)
	(segment
		(start 69.560948 -295.304464)
		(end 69.251068 -295.304464)
		(width 0.20066)
		(layer "F.Cu")
		(net "M_A_CPU1_SA_DQ<19>")
	)
	(segment
		(start 80.679798 -278.376126)
		(end 80.017112 -281.69362)
		(width 0.1016)
		(layer "F.Cu")
		(net "M_A_CPU1_SA_DQ<19>")
	)
	(segment
		(start 63.794132 -295.491662)
		(end 64.219074 -295.06672)
		(width 0.20066)
		(layer "F.Cu")
		(net "M_A_CPU1_SA_DQ<19>")
	)
	(segment
		(start 85.7377 -273.39544)
		(end 85.718396 -273.406616)
		(width 0.088646)
		(layer "F.Cu")
		(net "M_A_CPU1_SA_DQ<19>")
	)
	(segment
		(start 84.770214 -273.37766)
		(end 84.642706 -273.430492)
		(width 0.088646)
		(layer "F.Cu")
		(net "M_A_CPU1_SA_DQ<19>")
	)
	(segment
		(start 70.272148 -295.883584)
		(end 69.962268 -295.883584)
		(width 0.20066)
		(layer "F.Cu")
		(net "M_A_CPU1_SA_DQ<19>")
	)
	(segment
		(start 86.013544 -272.649188)
		(end 86.013544 -272.927064)
		(width 0.088646)
		(layer "F.Cu")
		(net "M_A_CPU1_SA_DQ<19>")
	)
	(segment
		(start 66.386202 -295.304464)
		(end 66.148458 -295.06672)
		(width 0.20066)
		(layer "F.Cu")
		(net "M_A_CPU1_SA_DQ<19>")
	)
	(segment
		(start 71.384668 -295.883584)
		(end 71.184008 -295.682924)
		(width 0.20066)
		(layer "F.Cu")
		(net "M_A_CPU1_SA_DQ<19>")
	)
	(segment
		(start 86.6775 -272.659094)
		(end 86.493096 -272.552668)
		(width 0.088646)
		(layer "F.Cu")
		(net "M_A_CPU1_SA_DQ<19>")
	)
	(segment
		(start 69.761608 -295.505124)
		(end 69.560948 -295.304464)
		(width 0.20066)
		(layer "F.Cu")
		(net "M_A_CPU1_SA_DQ<19>")
	)
	(segment
		(start 80.017112 -281.69362)
		(end 80.017112 -291.639244)
		(width 0.1016)
		(layer "F.Cu")
		(net "M_A_CPU1_SA_DQ<19>")
	)
	(segment
		(start 86.143846 -272.518886)
		(end 86.013544 -272.649188)
		(width 0.088646)
		(layer "F.Cu")
		(net "M_A_CPU1_SA_DQ<19>")
	)
	(segment
		(start 59.164728 -295.06672)
		(end 59.314842 -295.216834)
		(width 0.20066)
		(layer "F.Cu")
		(net "M_A_CPU1_SA_DQ<19>")
	)
	(segment
		(start 73.317608 -295.682924)
		(end 73.116948 -295.883584)
		(width 0.20066)
		(layer "F.Cu")
		(net "M_A_CPU1_SA_DQ<19>")
	)
	(segment
		(start 68.539868 -295.883584)
		(end 68.339208 -295.682924)
		(width 0.20066)
		(layer "F.Cu")
		(net "M_A_CPU1_SA_DQ<19>")
	)
	(segment
		(start 69.050408 -295.505124)
		(end 69.050408 -295.682924)
		(width 0.20066)
		(layer "F.Cu")
		(net "M_A_CPU1_SA_DQ<19>")
	)
	(segment
		(start 57.503314 -295.06672)
		(end 59.164728 -295.06672)
		(width 0.20066)
		(layer "F.Cu")
		(net "M_A_CPU1_SA_DQ<19>")
	)
	(segment
		(start 74.77887 -295.304464)
		(end 73.518268 -295.304464)
		(width 0.20066)
		(layer "F.Cu")
		(net "M_A_CPU1_SA_DQ<19>")
	)
	(segment
		(start 81.259172 -277.29434)
		(end 80.679798 -278.376126)
		(width 0.1016)
		(layer "F.Cu")
		(net "M_A_CPU1_SA_DQ<19>")
	)
	(segment
		(start 69.761608 -295.682924)
		(end 69.761608 -295.505124)
		(width 0.20066)
		(layer "F.Cu")
		(net "M_A_CPU1_SA_DQ<19>")
	)
	(segment
		(start 68.849748 -295.883584)
		(end 68.539868 -295.883584)
		(width 0.20066)
		(layer "F.Cu")
		(net "M_A_CPU1_SA_DQ<19>")
	)
	(segment
		(start 59.846718 -295.507156)
		(end 59.862212 -295.491662)
		(width 0.101854)
		(layer "F.Cu")
		(net "M_A_CPU1_SA_DQ<19>")
	)
	(segment
		(start 73.116948 -295.883584)
		(end 72.807068 -295.883584)
		(width 0.20066)
		(layer "F.Cu")
		(net "M_A_CPU1_SA_DQ<19>")
	)
	(segment
		(start 71.694548 -295.883584)
		(end 71.384668 -295.883584)
		(width 0.20066)
		(layer "F.Cu")
		(net "M_A_CPU1_SA_DQ<19>")
	)
	(segment
		(start 71.184008 -295.505124)
		(end 70.983348 -295.304464)
		(width 0.20066)
		(layer "F.Cu")
		(net "M_A_CPU1_SA_DQ<19>")
	)
	(segment
		(start 85.162644 -273.472656)
		(end 84.933282 -273.37766)
		(width 0.088646)
		(layer "F.Cu")
		(net "M_A_CPU1_SA_DQ<19>")
	)
	(segment
		(start 70.673468 -295.304464)
		(end 70.472808 -295.505124)
		(width 0.20066)
		(layer "F.Cu")
		(net "M_A_CPU1_SA_DQ<19>")
	)
	(segment
		(start 62.758828 -295.141904)
		(end 63.169038 -295.141904)
		(width 0.20066)
		(layer "F.Cu")
		(net "M_A_CPU1_SA_DQ<19>")
	)
	(segment
		(start 62.097412 -295.491662)
		(end 62.147958 -295.491662)
		(width 0.101854)
		(layer "F.Cu")
		(net "M_A_CPU1_SA_DQ<19>")
	)
	(segment
		(start 79.65313 -292.003226)
		(end 77.464412 -294.191944)
		(width 0.20066)
		(layer "F.Cu")
		(net "M_A_CPU1_SA_DQ<19>")
	)
	(segment
		(start 87.315294 -272.917158)
		(end 87.05596 -272.820384)
		(width 0.088646)
		(layer "F.Cu")
		(net "M_A_CPU1_SA_DQ<19>")
	)
	(segment
		(start 69.251068 -295.304464)
		(end 69.050408 -295.505124)
		(width 0.20066)
		(layer "F.Cu")
		(net "M_A_CPU1_SA_DQ<19>")
	)
	(segment
		(start 70.472808 -295.505124)
		(end 70.472808 -295.682924)
		(width 0.20066)
		(layer "F.Cu")
		(net "M_A_CPU1_SA_DQ<19>")
	)
	(segment
		(start 71.184008 -295.682924)
		(end 71.184008 -295.505124)
		(width 0.20066)
		(layer "F.Cu")
		(net "M_A_CPU1_SA_DQ<19>")
	)
	(segment
		(start 59.469528 -295.507156)
		(end 59.822842 -295.507156)
		(width 0.20066)
		(layer "F.Cu")
		(net "M_A_CPU1_SA_DQ<19>")
	)
	(segment
		(start 59.862212 -295.491662)
		(end 62.097412 -295.491662)
		(width 0.1016)
		(layer "F.Cu")
		(net "M_A_CPU1_SA_DQ<19>")
	)
	(segment
		(start 73.518268 -295.304464)
		(end 73.317608 -295.505124)
		(width 0.20066)
		(layer "F.Cu")
		(net "M_A_CPU1_SA_DQ<19>")
	)
	(segment
		(start 71.895208 -295.682924)
		(end 71.694548 -295.883584)
		(width 0.20066)
		(layer "F.Cu")
		(net "M_A_CPU1_SA_DQ<19>")
	)
	(segment
		(start 59.314842 -295.216834)
		(end 59.314842 -295.35247)
		(width 0.20066)
		(layer "F.Cu")
		(net "M_A_CPU1_SA_DQ<19>")
	)
	(segment
		(start 80.017112 -291.639244)
		(end 79.65313 -292.003226)
		(width 0.1016)
		(layer "F.Cu")
		(net "M_A_CPU1_SA_DQ<19>")
	)
	(segment
		(start 73.317608 -295.505124)
		(end 73.317608 -295.682924)
		(width 0.20066)
		(layer "F.Cu")
		(net "M_A_CPU1_SA_DQ<19>")
	)
	(segment
		(start 87.05596 -272.820384)
		(end 86.6775 -272.659094)
		(width 0.088646)
		(layer "F.Cu")
		(net "M_A_CPU1_SA_DQ<19>")
	)
	(segment
		(start 72.606408 -295.682924)
		(end 72.606408 -295.505124)
		(width 0.20066)
		(layer "F.Cu")
		(net "M_A_CPU1_SA_DQ<19>")
	)
	(segment
		(start 62.147958 -295.491662)
		(end 62.40907 -295.491662)
		(width 0.20066)
		(layer "F.Cu")
		(net "M_A_CPU1_SA_DQ<19>")
	)
	(segment
		(start 84.642706 -273.430492)
		(end 84.539328 -273.53387)
		(width 0.088646)
		(layer "F.Cu")
		(net "M_A_CPU1_SA_DQ<19>")
	)
	(segment
		(start 69.962268 -295.883584)
		(end 69.761608 -295.682924)
		(width 0.20066)
		(layer "F.Cu")
		(net "M_A_CPU1_SA_DQ<19>")
	)
	(segment
		(start 63.169038 -295.141904)
		(end 63.518796 -295.491662)
		(width 0.20066)
		(layer "F.Cu")
		(net "M_A_CPU1_SA_DQ<19>")
	)
	(segment
		(start 72.606408 -295.505124)
		(end 72.405748 -295.304464)
		(width 0.20066)
		(layer "F.Cu")
		(net "M_A_CPU1_SA_DQ<19>")
	)
	(segment
		(start 84.539328 -273.53387)
		(end 84.422488 -273.81581)
		(width 0.088646)
		(layer "F.Cu")
		(net "M_A_CPU1_SA_DQ<19>")
	)
	(segment
		(start 59.314842 -295.35247)
		(end 59.469528 -295.507156)
		(width 0.20066)
		(layer "F.Cu")
		(net "M_A_CPU1_SA_DQ<19>")
	)
	(segment
		(start 84.422488 -274.131024)
		(end 83.947254 -274.606258)
		(width 0.088646)
		(layer "F.Cu")
		(net "M_A_CPU1_SA_DQ<19>")
	)
	(segment
		(start 84.933282 -273.37766)
		(end 84.770214 -273.37766)
		(width 0.088646)
		(layer "F.Cu")
		(net "M_A_CPU1_SA_DQ<19>")
	)
	(segment
		(start 86.367366 -272.518886)
		(end 86.143846 -272.518886)
		(width 0.088646)
		(layer "F.Cu")
		(net "M_A_CPU1_SA_DQ<19>")
	)
	(segment
		(start 68.339208 -295.682924)
		(end 68.339208 -295.505124)
		(width 0.20066)
		(layer "F.Cu")
		(net "M_A_CPU1_SA_DQ<19>")
	)
	(segment
		(start 71.895208 -295.505124)
		(end 71.895208 -295.682924)
		(width 0.20066)
		(layer "F.Cu")
		(net "M_A_CPU1_SA_DQ<19>")
	)
	(segment
		(start 64.219074 -295.06672)
		(end 65.047114 -295.06672)
		(width 0.20066)
		(layer "F.Cu")
		(net "M_A_CPU1_SA_DQ<19>")
	)
	(segment
		(start 66.148458 -295.06672)
		(end 65.047114 -295.06672)
		(width 0.20066)
		(layer "F.Cu")
		(net "M_A_CPU1_SA_DQ<19>")
	)
	(segment
		(start 68.339208 -295.505124)
		(end 68.138548 -295.304464)
		(width 0.20066)
		(layer "F.Cu")
		(net "M_A_CPU1_SA_DQ<19>")
	)
	(arc
		(start 85.587078 -273.468338)
		(mid 85.574952 -273.471588)
		(end 85.56244 -273.472656)
		(width 0.088646)
		(layer "F.Cu")
		(net "M_A_CPU1_SA_DQ<19>")
	)
	(arc
		(start 86.493096 -272.552668)
		(mid 86.432458 -272.527477)
		(end 86.367366 -272.518886)
		(width 0.088646)
		(layer "F.Cu")
		(net "M_A_CPU1_SA_DQ<19>")
	)
	(arc
		(start 85.718396 -273.406616)
		(mid 85.654053 -273.440276)
		(end 85.587078 -273.468338)
		(width 0.088646)
		(layer "F.Cu")
		(net "M_A_CPU1_SA_DQ<19>")
	)
	(arc
		(start 86.013544 -272.927064)
		(mid 85.937263 -273.197554)
		(end 85.7377 -273.39544)
		(width 0.088646)
		(layer "F.Cu")
		(net "M_A_CPU1_SA_DQ<19>")
	)
	(segment
		(start 62.37605 -296.341546)
		(end 62.51702 -296.482516)
		(width 0.20066)
		(layer "F.Cu")
		(net "M_A_CPU1_SA_DQ<18>")
	)
	(segment
		(start 70.486524 -297.594274)
		(end 70.176644 -297.594274)
		(width 0.20066)
		(layer "F.Cu")
		(net "M_A_CPU1_SA_DQ<18>")
	)
	(segment
		(start 84.880196 -274.522692)
		(end 84.880196 -274.539202)
		(width 0.088646)
		(layer "F.Cu")
		(net "M_A_CPU1_SA_DQ<18>")
	)
	(segment
		(start 76.95184 -295.795954)
		(end 76.843382 -296.057828)
		(width 0.20066)
		(layer "F.Cu")
		(net "M_A_CPU1_SA_DQ<18>")
	)
	(segment
		(start 67.55257 -297.163998)
		(end 67.155314 -296.766742)
		(width 0.20066)
		(layer "F.Cu")
		(net "M_A_CPU1_SA_DQ<18>")
	)
	(segment
		(start 86.076536 -274.843748)
		(end 85.925152 -274.847304)
		(width 0.088646)
		(layer "F.Cu")
		(net "M_A_CPU1_SA_DQ<18>")
	)
	(segment
		(start 85.552534 -274.20824)
		(end 85.267038 -274.20824)
		(width 0.088646)
		(layer "F.Cu")
		(net "M_A_CPU1_SA_DQ<18>")
	)
	(segment
		(start 63.417196 -296.766742)
		(end 65.047114 -296.766742)
		(width 0.20066)
		(layer "F.Cu")
		(net "M_A_CPU1_SA_DQ<18>")
	)
	(segment
		(start 67.155314 -296.766742)
		(end 65.047114 -296.766742)
		(width 0.20066)
		(layer "F.Cu")
		(net "M_A_CPU1_SA_DQ<18>")
	)
	(segment
		(start 69.975984 -297.364658)
		(end 69.775324 -297.163998)
		(width 0.20066)
		(layer "F.Cu")
		(net "M_A_CPU1_SA_DQ<18>")
	)
	(segment
		(start 76.962762 -296.346118)
		(end 76.854304 -296.608246)
		(width 0.20066)
		(layer "F.Cu")
		(net "M_A_CPU1_SA_DQ<18>")
	)
	(segment
		(start 86.375494 -274.54479)
		(end 86.076536 -274.843748)
		(width 0.088646)
		(layer "F.Cu")
		(net "M_A_CPU1_SA_DQ<18>")
	)
	(segment
		(start 85.925152 -274.847304)
		(end 85.831934 -274.762722)
		(width 0.088646)
		(layer "F.Cu")
		(net "M_A_CPU1_SA_DQ<18>")
	)
	(segment
		(start 85.806026 -274.426426)
		(end 85.755226 -274.324826)
		(width 0.088646)
		(layer "F.Cu")
		(net "M_A_CPU1_SA_DQ<18>")
	)
	(segment
		(start 69.975984 -297.393614)
		(end 69.975984 -297.364658)
		(width 0.20066)
		(layer "F.Cu")
		(net "M_A_CPU1_SA_DQ<18>")
	)
	(segment
		(start 81.26095 -278.584406)
		(end 80.626712 -281.756358)
		(width 0.1016)
		(layer "F.Cu")
		(net "M_A_CPU1_SA_DQ<18>")
	)
	(segment
		(start 59.102752 -296.521378)
		(end 59.296808 -296.327322)
		(width 0.20066)
		(layer "F.Cu")
		(net "M_A_CPU1_SA_DQ<18>")
	)
	(segment
		(start 59.102752 -296.66438)
		(end 59.102752 -296.521378)
		(width 0.20066)
		(layer "F.Cu")
		(net "M_A_CPU1_SA_DQ<18>")
	)
	(segment
		(start 72.109584 -297.364658)
		(end 72.109584 -297.393614)
		(width 0.20066)
		(layer "F.Cu")
		(net "M_A_CPU1_SA_DQ<18>")
	)
	(segment
		(start 84.380324 -275.039074)
		(end 81.751932 -277.667466)
		(width 0.1016)
		(layer "F.Cu")
		(net "M_A_CPU1_SA_DQ<18>")
	)
	(segment
		(start 69.264784 -297.364658)
		(end 69.264784 -297.393614)
		(width 0.20066)
		(layer "F.Cu")
		(net "M_A_CPU1_SA_DQ<18>")
	)
	(segment
		(start 71.599044 -297.594274)
		(end 71.398384 -297.393614)
		(width 0.20066)
		(layer "F.Cu")
		(net "M_A_CPU1_SA_DQ<18>")
	)
	(segment
		(start 85.831934 -274.762722)
		(end 85.806026 -274.502626)
		(width 0.088646)
		(layer "F.Cu")
		(net "M_A_CPU1_SA_DQ<18>")
	)
	(segment
		(start 63.067946 -296.968672)
		(end 63.319406 -296.864532)
		(width 0.20066)
		(layer "F.Cu")
		(net "M_A_CPU1_SA_DQ<18>")
	)
	(segment
		(start 57.503314 -296.766742)
		(end 59.00039 -296.766742)
		(width 0.20066)
		(layer "F.Cu")
		(net "M_A_CPU1_SA_DQ<18>")
	)
	(segment
		(start 76.186284 -296.330116)
		(end 75.92441 -296.221658)
		(width 0.20066)
		(layer "F.Cu")
		(net "M_A_CPU1_SA_DQ<18>")
	)
	(segment
		(start 72.310244 -297.163998)
		(end 72.109584 -297.364658)
		(width 0.20066)
		(layer "F.Cu")
		(net "M_A_CPU1_SA_DQ<18>")
	)
	(segment
		(start 69.465444 -297.163998)
		(end 69.264784 -297.364658)
		(width 0.20066)
		(layer "F.Cu")
		(net "M_A_CPU1_SA_DQ<18>")
	)
	(segment
		(start 69.775324 -297.163998)
		(end 69.465444 -297.163998)
		(width 0.20066)
		(layer "F.Cu")
		(net "M_A_CPU1_SA_DQ<18>")
	)
	(segment
		(start 71.197724 -297.163998)
		(end 70.887844 -297.163998)
		(width 0.20066)
		(layer "F.Cu")
		(net "M_A_CPU1_SA_DQ<18>")
	)
	(segment
		(start 85.14334 -274.259548)
		(end 84.880196 -274.522692)
		(width 0.088646)
		(layer "F.Cu")
		(net "M_A_CPU1_SA_DQ<18>")
	)
	(segment
		(start 69.064124 -297.594274)
		(end 68.754244 -297.594274)
		(width 0.20066)
		(layer "F.Cu")
		(net "M_A_CPU1_SA_DQ<18>")
	)
	(segment
		(start 68.553584 -297.364658)
		(end 68.352924 -297.163998)
		(width 0.20066)
		(layer "F.Cu")
		(net "M_A_CPU1_SA_DQ<18>")
	)
	(segment
		(start 70.687184 -297.364658)
		(end 70.687184 -297.393614)
		(width 0.20066)
		(layer "F.Cu")
		(net "M_A_CPU1_SA_DQ<18>")
	)
	(segment
		(start 75.253342 -297.271694)
		(end 74.991468 -297.163236)
		(width 0.20066)
		(layer "F.Cu")
		(net "M_A_CPU1_SA_DQ<18>")
	)
	(segment
		(start 75.637644 -296.34053)
		(end 75.529186 -296.602404)
		(width 0.20066)
		(layer "F.Cu")
		(net "M_A_CPU1_SA_DQ<18>")
	)
	(segment
		(start 80.626712 -292.844982)
		(end 80.471772 -292.999922)
		(width 0.1016)
		(layer "F.Cu")
		(net "M_A_CPU1_SA_DQ<18>")
	)
	(segment
		(start 62.147958 -296.341546)
		(end 62.37605 -296.341546)
		(width 0.20066)
		(layer "F.Cu")
		(net "M_A_CPU1_SA_DQ<18>")
	)
	(segment
		(start 59.862212 -296.341546)
		(end 62.097412 -296.341546)
		(width 0.1016)
		(layer "F.Cu")
		(net "M_A_CPU1_SA_DQ<18>")
	)
	(segment
		(start 76.854304 -296.608246)
		(end 76.567538 -296.727118)
		(width 0.20066)
		(layer "F.Cu")
		(net "M_A_CPU1_SA_DQ<18>")
	)
	(segment
		(start 62.51702 -296.482516)
		(end 62.51702 -296.722038)
		(width 0.20066)
		(layer "F.Cu")
		(net "M_A_CPU1_SA_DQ<18>")
	)
	(segment
		(start 70.176644 -297.594274)
		(end 69.975984 -297.393614)
		(width 0.20066)
		(layer "F.Cu")
		(net "M_A_CPU1_SA_DQ<18>")
	)
	(segment
		(start 72.109584 -297.393614)
		(end 71.908924 -297.594274)
		(width 0.20066)
		(layer "F.Cu")
		(net "M_A_CPU1_SA_DQ<18>")
	)
	(segment
		(start 62.763654 -296.968672)
		(end 63.067946 -296.968672)
		(width 0.20066)
		(layer "F.Cu")
		(net "M_A_CPU1_SA_DQ<18>")
	)
	(segment
		(start 76.305664 -296.61866)
		(end 76.186284 -296.330116)
		(width 0.20066)
		(layer "F.Cu")
		(net "M_A_CPU1_SA_DQ<18>")
	)
	(segment
		(start 74.610214 -296.766234)
		(end 73.650094 -297.163998)
		(width 0.20066)
		(layer "F.Cu")
		(net "M_A_CPU1_SA_DQ<18>")
	)
	(segment
		(start 59.296808 -296.327322)
		(end 59.822842 -296.327322)
		(width 0.20066)
		(layer "F.Cu")
		(net "M_A_CPU1_SA_DQ<18>")
	)
	(segment
		(start 68.553584 -297.393614)
		(end 68.553584 -297.364658)
		(width 0.20066)
		(layer "F.Cu")
		(net "M_A_CPU1_SA_DQ<18>")
	)
	(segment
		(start 84.880196 -274.539202)
		(end 84.380324 -275.039074)
		(width 0.088646)
		(layer "F.Cu")
		(net "M_A_CPU1_SA_DQ<18>")
	)
	(segment
		(start 76.567538 -296.727118)
		(end 76.305664 -296.61866)
		(width 0.20066)
		(layer "F.Cu")
		(net "M_A_CPU1_SA_DQ<18>")
	)
	(segment
		(start 71.908924 -297.594274)
		(end 71.599044 -297.594274)
		(width 0.20066)
		(layer "F.Cu")
		(net "M_A_CPU1_SA_DQ<18>")
	)
	(segment
		(start 68.754244 -297.594274)
		(end 68.553584 -297.393614)
		(width 0.20066)
		(layer "F.Cu")
		(net "M_A_CPU1_SA_DQ<18>")
	)
	(segment
		(start 75.92441 -296.221658)
		(end 75.637644 -296.34053)
		(width 0.20066)
		(layer "F.Cu")
		(net "M_A_CPU1_SA_DQ<18>")
	)
	(segment
		(start 62.097412 -296.341546)
		(end 62.147958 -296.341546)
		(width 0.101854)
		(layer "F.Cu")
		(net "M_A_CPU1_SA_DQ<18>")
	)
	(segment
		(start 69.264784 -297.393614)
		(end 69.064124 -297.594274)
		(width 0.20066)
		(layer "F.Cu")
		(net "M_A_CPU1_SA_DQ<18>")
	)
	(segment
		(start 70.687184 -297.393614)
		(end 70.486524 -297.594274)
		(width 0.20066)
		(layer "F.Cu")
		(net "M_A_CPU1_SA_DQ<18>")
	)
	(segment
		(start 74.991468 -297.163236)
		(end 74.872088 -296.874692)
		(width 0.20066)
		(layer "F.Cu")
		(net "M_A_CPU1_SA_DQ<18>")
	)
	(segment
		(start 74.872088 -296.874692)
		(end 74.610214 -296.766234)
		(width 0.20066)
		(layer "F.Cu")
		(net "M_A_CPU1_SA_DQ<18>")
	)
	(segment
		(start 59.847988 -296.327322)
		(end 59.862212 -296.341546)
		(width 0.101854)
		(layer "F.Cu")
		(net "M_A_CPU1_SA_DQ<18>")
	)
	(segment
		(start 62.51702 -296.722038)
		(end 62.763654 -296.968672)
		(width 0.20066)
		(layer "F.Cu")
		(net "M_A_CPU1_SA_DQ<18>")
	)
	(segment
		(start 75.648566 -296.890694)
		(end 75.540108 -297.152822)
		(width 0.20066)
		(layer "F.Cu")
		(net "M_A_CPU1_SA_DQ<18>")
	)
	(segment
		(start 68.352924 -297.163998)
		(end 67.55257 -297.163998)
		(width 0.20066)
		(layer "F.Cu")
		(net "M_A_CPU1_SA_DQ<18>")
	)
	(segment
		(start 73.650094 -297.163998)
		(end 72.310244 -297.163998)
		(width 0.20066)
		(layer "F.Cu")
		(net "M_A_CPU1_SA_DQ<18>")
	)
	(segment
		(start 80.471772 -292.999922)
		(end 78.186788 -295.284906)
		(width 0.20066)
		(layer "F.Cu")
		(net "M_A_CPU1_SA_DQ<18>")
	)
	(segment
		(start 85.806026 -274.502626)
		(end 85.806026 -274.426426)
		(width 0.088646)
		(layer "F.Cu")
		(net "M_A_CPU1_SA_DQ<18>")
	)
	(segment
		(start 59.822842 -296.327322)
		(end 59.847988 -296.327322)
		(width 0.101854)
		(layer "F.Cu")
		(net "M_A_CPU1_SA_DQ<18>")
	)
	(segment
		(start 71.398384 -297.364658)
		(end 71.197724 -297.163998)
		(width 0.20066)
		(layer "F.Cu")
		(net "M_A_CPU1_SA_DQ<18>")
	)
	(segment
		(start 75.540108 -297.152822)
		(end 75.253342 -297.271694)
		(width 0.20066)
		(layer "F.Cu")
		(net "M_A_CPU1_SA_DQ<18>")
	)
	(segment
		(start 71.398384 -297.393614)
		(end 71.398384 -297.364658)
		(width 0.20066)
		(layer "F.Cu")
		(net "M_A_CPU1_SA_DQ<18>")
	)
	(segment
		(start 85.267038 -274.20824)
		(end 85.14334 -274.259548)
		(width 0.088646)
		(layer "F.Cu")
		(net "M_A_CPU1_SA_DQ<18>")
	)
	(segment
		(start 85.755226 -274.324826)
		(end 85.635338 -274.235672)
		(width 0.088646)
		(layer "F.Cu")
		(net "M_A_CPU1_SA_DQ<18>")
	)
	(segment
		(start 76.843382 -296.057828)
		(end 76.962762 -296.346118)
		(width 0.20066)
		(layer "F.Cu")
		(net "M_A_CPU1_SA_DQ<18>")
	)
	(segment
		(start 80.626712 -281.756358)
		(end 80.626712 -292.844982)
		(width 0.1016)
		(layer "F.Cu")
		(net "M_A_CPU1_SA_DQ<18>")
	)
	(segment
		(start 70.887844 -297.163998)
		(end 70.687184 -297.364658)
		(width 0.20066)
		(layer "F.Cu")
		(net "M_A_CPU1_SA_DQ<18>")
	)
	(segment
		(start 81.751932 -277.667466)
		(end 81.26095 -278.584406)
		(width 0.1016)
		(layer "F.Cu")
		(net "M_A_CPU1_SA_DQ<18>")
	)
	(segment
		(start 78.186788 -295.284906)
		(end 76.95184 -295.795954)
		(width 0.20066)
		(layer "F.Cu")
		(net "M_A_CPU1_SA_DQ<18>")
	)
	(segment
		(start 59.00039 -296.766742)
		(end 59.102752 -296.66438)
		(width 0.20066)
		(layer "F.Cu")
		(net "M_A_CPU1_SA_DQ<18>")
	)
	(segment
		(start 63.319406 -296.864532)
		(end 63.417196 -296.766742)
		(width 0.20066)
		(layer "F.Cu")
		(net "M_A_CPU1_SA_DQ<18>")
	)
	(segment
		(start 75.529186 -296.602404)
		(end 75.648566 -296.890694)
		(width 0.20066)
		(layer "F.Cu")
		(net "M_A_CPU1_SA_DQ<18>")
	)
	(arc
		(start 85.635338 -274.235672)
		(mid 85.596141 -274.215312)
		(end 85.552534 -274.20824)
		(width 0.088646)
		(layer "F.Cu")
		(net "M_A_CPU1_SA_DQ<18>")
	)
	(segment
		(start 53.403246 -295.916604)
		(end 54.02707 -295.916604)
		(width 0.20066)
		(layer "F.Cu")
		(net "M_A_CPU1_SA_DQ<17>")
	)
	(segment
		(start 77.833474 -294.733472)
		(end 73.509886 -296.524426)
		(width 0.20066)
		(layer "F.Cu")
		(net "M_A_CPU1_SA_DQ<17>")
	)
	(segment
		(start 73.509886 -296.524426)
		(end 67.955922 -296.524426)
		(width 0.20066)
		(layer "F.Cu")
		(net "M_A_CPU1_SA_DQ<17>")
	)
	(segment
		(start 80.971136 -278.47798)
		(end 80.321912 -281.726132)
		(width 0.1016)
		(layer "F.Cu")
		(net "M_A_CPU1_SA_DQ<17>")
	)
	(segment
		(start 63.977012 -296.36085)
		(end 63.488316 -296.36085)
		(width 0.20066)
		(layer "F.Cu")
		(net "M_A_CPU1_SA_DQ<17>")
	)
	(segment
		(start 58.643012 -295.491662)
		(end 58.704226 -295.491662)
		(width 0.101854)
		(layer "F.Cu")
		(net "M_A_CPU1_SA_DQ<17>")
	)
	(segment
		(start 56.408574 -295.471342)
		(end 56.428894 -295.491662)
		(width 0.101854)
		(layer "F.Cu")
		(net "M_A_CPU1_SA_DQ<17>")
	)
	(segment
		(start 64.06388 -296.341546)
		(end 64.044576 -296.36085)
		(width 0.101854)
		(layer "F.Cu")
		(net "M_A_CPU1_SA_DQ<17>")
	)
	(segment
		(start 85.021674 -274.09267)
		(end 84.539582 -274.574762)
		(width 0.088646)
		(layer "F.Cu")
		(net "M_A_CPU1_SA_DQ<17>")
	)
	(segment
		(start 84.323936 -274.66417)
		(end 84.164678 -274.823428)
		(width 0.088646)
		(layer "F.Cu")
		(net "M_A_CPU1_SA_DQ<17>")
	)
	(segment
		(start 85.202014 -274.017994)
		(end 85.021674 -274.09267)
		(width 0.088646)
		(layer "F.Cu")
		(net "M_A_CPU1_SA_DQ<17>")
	)
	(segment
		(start 66.15049 -296.348912)
		(end 66.143124 -296.341546)
		(width 0.101854)
		(layer "F.Cu")
		(net "M_A_CPU1_SA_DQ<17>")
	)
	(segment
		(start 59.271662 -295.916604)
		(end 60.947046 -295.916604)
		(width 0.20066)
		(layer "F.Cu")
		(net "M_A_CPU1_SA_DQ<17>")
	)
	(segment
		(start 81.504282 -277.483824)
		(end 80.971136 -278.47798)
		(width 0.1016)
		(layer "F.Cu")
		(net "M_A_CPU1_SA_DQ<17>")
	)
	(segment
		(start 80.108298 -292.458648)
		(end 77.833474 -294.733472)
		(width 0.20066)
		(layer "F.Cu")
		(net "M_A_CPU1_SA_DQ<17>")
	)
	(segment
		(start 56.428894 -295.491662)
		(end 58.643012 -295.491662)
		(width 0.1016)
		(layer "F.Cu")
		(net "M_A_CPU1_SA_DQ<17>")
	)
	(segment
		(start 85.57895 -274.017994)
		(end 85.202014 -274.017994)
		(width 0.088646)
		(layer "F.Cu")
		(net "M_A_CPU1_SA_DQ<17>")
	)
	(segment
		(start 86.525862 -273.94789)
		(end 86.209886 -274.084034)
		(width 0.088646)
		(layer "F.Cu")
		(net "M_A_CPU1_SA_DQ<17>")
	)
	(segment
		(start 56.37911 -295.471342)
		(end 56.408574 -295.471342)
		(width 0.101854)
		(layer "F.Cu")
		(net "M_A_CPU1_SA_DQ<17>")
	)
	(segment
		(start 66.291968 -296.348912)
		(end 66.186812 -296.348912)
		(width 0.20066)
		(layer "F.Cu")
		(net "M_A_CPU1_SA_DQ<17>")
	)
	(segment
		(start 67.955922 -296.524426)
		(end 67.50685 -296.075354)
		(width 0.20066)
		(layer "F.Cu")
		(net "M_A_CPU1_SA_DQ<17>")
	)
	(segment
		(start 55.097934 -295.471342)
		(end 56.37911 -295.471342)
		(width 0.20066)
		(layer "F.Cu")
		(net "M_A_CPU1_SA_DQ<17>")
	)
	(segment
		(start 66.143124 -296.341546)
		(end 64.06388 -296.341546)
		(width 0.1016)
		(layer "F.Cu")
		(net "M_A_CPU1_SA_DQ<17>")
	)
	(segment
		(start 64.044576 -296.36085)
		(end 63.977012 -296.36085)
		(width 0.101854)
		(layer "F.Cu")
		(net "M_A_CPU1_SA_DQ<17>")
	)
	(segment
		(start 80.321912 -281.726132)
		(end 80.321912 -292.245034)
		(width 0.1016)
		(layer "F.Cu")
		(net "M_A_CPU1_SA_DQ<17>")
	)
	(segment
		(start 67.50685 -296.075354)
		(end 66.604896 -296.075354)
		(width 0.20066)
		(layer "F.Cu")
		(net "M_A_CPU1_SA_DQ<17>")
	)
	(segment
		(start 54.027324 -295.91635)
		(end 54.279292 -296.168318)
		(width 0.20066)
		(layer "F.Cu")
		(net "M_A_CPU1_SA_DQ<17>")
	)
	(segment
		(start 66.186812 -296.348912)
		(end 66.15049 -296.348912)
		(width 0.101854)
		(layer "F.Cu")
		(net "M_A_CPU1_SA_DQ<17>")
	)
	(segment
		(start 58.704226 -295.491662)
		(end 58.84672 -295.491662)
		(width 0.20066)
		(layer "F.Cu")
		(net "M_A_CPU1_SA_DQ<17>")
	)
	(segment
		(start 84.539582 -274.574762)
		(end 84.323936 -274.66417)
		(width 0.088646)
		(layer "F.Cu")
		(net "M_A_CPU1_SA_DQ<17>")
	)
	(segment
		(start 54.897528 -295.93413)
		(end 54.897528 -295.671748)
		(width 0.20066)
		(layer "F.Cu")
		(net "M_A_CPU1_SA_DQ<17>")
	)
	(segment
		(start 66.296032 -296.344848)
		(end 66.291968 -296.348912)
		(width 0.20066)
		(layer "F.Cu")
		(net "M_A_CPU1_SA_DQ<17>")
	)
	(segment
		(start 63.488316 -296.36085)
		(end 62.415928 -295.916604)
		(width 0.20066)
		(layer "F.Cu")
		(net "M_A_CPU1_SA_DQ<17>")
	)
	(segment
		(start 58.84672 -295.491662)
		(end 59.271662 -295.916604)
		(width 0.20066)
		(layer "F.Cu")
		(net "M_A_CPU1_SA_DQ<17>")
	)
	(segment
		(start 54.66334 -296.168318)
		(end 54.897528 -295.93413)
		(width 0.20066)
		(layer "F.Cu")
		(net "M_A_CPU1_SA_DQ<17>")
	)
	(segment
		(start 54.897528 -295.671748)
		(end 55.097934 -295.471342)
		(width 0.20066)
		(layer "F.Cu")
		(net "M_A_CPU1_SA_DQ<17>")
	)
	(segment
		(start 66.335402 -296.344848)
		(end 66.296032 -296.344848)
		(width 0.20066)
		(layer "F.Cu")
		(net "M_A_CPU1_SA_DQ<17>")
	)
	(segment
		(start 84.164678 -274.823428)
		(end 81.504282 -277.483824)
		(width 0.1016)
		(layer "F.Cu")
		(net "M_A_CPU1_SA_DQ<17>")
	)
	(segment
		(start 54.02707 -295.916604)
		(end 54.027324 -295.91635)
		(width 0.20066)
		(layer "F.Cu")
		(net "M_A_CPU1_SA_DQ<17>")
	)
	(segment
		(start 62.415928 -295.916604)
		(end 60.947046 -295.916604)
		(width 0.20066)
		(layer "F.Cu")
		(net "M_A_CPU1_SA_DQ<17>")
	)
	(segment
		(start 54.279292 -296.168318)
		(end 54.66334 -296.168318)
		(width 0.20066)
		(layer "F.Cu")
		(net "M_A_CPU1_SA_DQ<17>")
	)
	(segment
		(start 66.604896 -296.075354)
		(end 66.335402 -296.344848)
		(width 0.20066)
		(layer "F.Cu")
		(net "M_A_CPU1_SA_DQ<17>")
	)
	(segment
		(start 80.321912 -292.245034)
		(end 80.108298 -292.458648)
		(width 0.1016)
		(layer "F.Cu")
		(net "M_A_CPU1_SA_DQ<17>")
	)
	(arc
		(start 85.718396 -274.055332)
		(mid 85.651132 -274.027473)
		(end 85.57895 -274.017994)
		(width 0.088646)
		(layer "F.Cu")
		(net "M_A_CPU1_SA_DQ<17>")
	)
	(arc
		(start 86.209886 -274.084034)
		(mid 85.960739 -274.127884)
		(end 85.718396 -274.055332)
		(width 0.088646)
		(layer "F.Cu")
		(net "M_A_CPU1_SA_DQ<17>")
	)
	(arc
		(start 86.845648 -273.730974)
		(mid 86.69606 -273.854627)
		(end 86.525862 -273.94789)
		(width 0.088646)
		(layer "F.Cu")
		(net "M_A_CPU1_SA_DQ<17>")
	)
	(segment
		(start 63.737998 -297.175682)
		(end 63.16726 -297.36923)
		(width 0.20066)
		(layer "F.Cu")
		(net "M_A_CPU1_SA_DQ<16>")
	)
	(segment
		(start 54.66334 -297.86834)
		(end 54.897528 -297.634152)
		(width 0.20066)
		(layer "F.Cu")
		(net "M_A_CPU1_SA_DQ<16>")
	)
	(segment
		(start 64.013334 -297.175682)
		(end 63.951612 -297.175682)
		(width 0.101854)
		(layer "F.Cu")
		(net "M_A_CPU1_SA_DQ<16>")
	)
	(segment
		(start 85.055456 -274.795488)
		(end 84.59597 -275.254974)
		(width 0.088646)
		(layer "F.Cu")
		(net "M_A_CPU1_SA_DQ<16>")
	)
	(segment
		(start 66.397124 -297.174412)
		(end 66.161412 -297.174412)
		(width 0.20066)
		(layer "F.Cu")
		(net "M_A_CPU1_SA_DQ<16>")
	)
	(segment
		(start 63.951612 -297.175682)
		(end 63.737998 -297.175682)
		(width 0.20066)
		(layer "F.Cu")
		(net "M_A_CPU1_SA_DQ<16>")
	)
	(segment
		(start 54.02707 -297.616626)
		(end 54.027324 -297.616372)
		(width 0.20066)
		(layer "F.Cu")
		(net "M_A_CPU1_SA_DQ<16>")
	)
	(segment
		(start 80.931512 -281.787854)
		(end 80.931512 -293.44747)
		(width 0.1016)
		(layer "F.Cu")
		(net "M_A_CPU1_SA_DQ<16>")
	)
	(segment
		(start 81.551272 -278.688292)
		(end 80.931512 -281.787854)
		(width 0.1016)
		(layer "F.Cu")
		(net "M_A_CPU1_SA_DQ<16>")
	)
	(segment
		(start 59.050682 -297.191684)
		(end 59.475624 -297.616626)
		(width 0.20066)
		(layer "F.Cu")
		(net "M_A_CPU1_SA_DQ<16>")
	)
	(segment
		(start 66.116708 -297.174412)
		(end 66.099436 -297.191684)
		(width 0.101854)
		(layer "F.Cu")
		(net "M_A_CPU1_SA_DQ<16>")
	)
	(segment
		(start 67.456558 -298.233846)
		(end 66.397124 -297.174412)
		(width 0.20066)
		(layer "F.Cu")
		(net "M_A_CPU1_SA_DQ<16>")
	)
	(segment
		(start 55.060088 -297.183556)
		(end 56.37911 -297.183556)
		(width 0.20066)
		(layer "F.Cu")
		(net "M_A_CPU1_SA_DQ<16>")
	)
	(segment
		(start 80.595216 -293.783766)
		(end 77.171042 -297.20794)
		(width 0.20066)
		(layer "F.Cu")
		(net "M_A_CPU1_SA_DQ<16>")
	)
	(segment
		(start 54.897528 -297.346116)
		(end 55.060088 -297.183556)
		(width 0.20066)
		(layer "F.Cu")
		(net "M_A_CPU1_SA_DQ<16>")
	)
	(segment
		(start 66.161412 -297.174412)
		(end 66.116708 -297.174412)
		(width 0.101854)
		(layer "F.Cu")
		(net "M_A_CPU1_SA_DQ<16>")
	)
	(segment
		(start 53.403246 -297.616626)
		(end 54.02707 -297.616626)
		(width 0.20066)
		(layer "F.Cu")
		(net "M_A_CPU1_SA_DQ<16>")
	)
	(segment
		(start 58.704226 -297.191684)
		(end 59.050682 -297.191684)
		(width 0.20066)
		(layer "F.Cu")
		(net "M_A_CPU1_SA_DQ<16>")
	)
	(segment
		(start 62.034674 -297.616626)
		(end 60.947046 -297.616626)
		(width 0.20066)
		(layer "F.Cu")
		(net "M_A_CPU1_SA_DQ<16>")
	)
	(segment
		(start 85.435694 -274.54479)
		(end 85.055456 -274.795488)
		(width 0.088646)
		(layer "F.Cu")
		(net "M_A_CPU1_SA_DQ<16>")
	)
	(segment
		(start 58.668412 -297.191684)
		(end 58.704226 -297.191684)
		(width 0.101854)
		(layer "F.Cu")
		(net "M_A_CPU1_SA_DQ<16>")
	)
	(segment
		(start 84.59597 -275.254974)
		(end 82.000344 -277.8506)
		(width 0.1016)
		(layer "F.Cu")
		(net "M_A_CPU1_SA_DQ<16>")
	)
	(segment
		(start 54.897528 -297.634152)
		(end 54.897528 -297.346116)
		(width 0.20066)
		(layer "F.Cu")
		(net "M_A_CPU1_SA_DQ<16>")
	)
	(segment
		(start 59.475624 -297.616626)
		(end 60.947046 -297.616626)
		(width 0.20066)
		(layer "F.Cu")
		(net "M_A_CPU1_SA_DQ<16>")
	)
	(segment
		(start 63.16726 -297.36923)
		(end 62.034674 -297.616626)
		(width 0.20066)
		(layer "F.Cu")
		(net "M_A_CPU1_SA_DQ<16>")
	)
	(segment
		(start 56.37911 -297.183556)
		(end 56.425084 -297.183556)
		(width 0.101854)
		(layer "F.Cu")
		(net "M_A_CPU1_SA_DQ<16>")
	)
	(segment
		(start 82.000344 -277.8506)
		(end 81.551272 -278.688292)
		(width 0.1016)
		(layer "F.Cu")
		(net "M_A_CPU1_SA_DQ<16>")
	)
	(segment
		(start 54.027324 -297.616372)
		(end 54.279292 -297.86834)
		(width 0.20066)
		(layer "F.Cu")
		(net "M_A_CPU1_SA_DQ<16>")
	)
	(segment
		(start 80.931512 -293.44747)
		(end 80.595216 -293.783766)
		(width 0.1016)
		(layer "F.Cu")
		(net "M_A_CPU1_SA_DQ<16>")
	)
	(segment
		(start 74.694034 -298.233846)
		(end 67.456558 -298.233846)
		(width 0.20066)
		(layer "F.Cu")
		(net "M_A_CPU1_SA_DQ<16>")
	)
	(segment
		(start 64.029336 -297.191684)
		(end 64.013334 -297.175682)
		(width 0.101854)
		(layer "F.Cu")
		(net "M_A_CPU1_SA_DQ<16>")
	)
	(segment
		(start 56.425084 -297.183556)
		(end 56.433212 -297.191684)
		(width 0.101854)
		(layer "F.Cu")
		(net "M_A_CPU1_SA_DQ<16>")
	)
	(segment
		(start 56.433212 -297.191684)
		(end 58.668412 -297.191684)
		(width 0.1016)
		(layer "F.Cu")
		(net "M_A_CPU1_SA_DQ<16>")
	)
	(segment
		(start 66.099436 -297.191684)
		(end 64.029336 -297.191684)
		(width 0.1016)
		(layer "F.Cu")
		(net "M_A_CPU1_SA_DQ<16>")
	)
	(segment
		(start 54.279292 -297.86834)
		(end 54.66334 -297.86834)
		(width 0.20066)
		(layer "F.Cu")
		(net "M_A_CPU1_SA_DQ<16>")
	)
	(segment
		(start 77.171042 -297.20794)
		(end 74.694034 -298.233846)
		(width 0.20066)
		(layer "F.Cu")
		(net "M_A_CPU1_SA_DQ<16>")
	)
	(segment
		(start 62.097412 -298.891706)
		(end 59.862212 -298.891706)
		(width 0.1016)
		(layer "F.Cu")
		(net "M_A_CPU1_SA_DQ<15>")
	)
	(segment
		(start 64.02959 -298.630848)
		(end 63.522098 -298.630848)
		(width 0.20066)
		(layer "F.Cu")
		(net "M_A_CPU1_SA_DQ<15>")
	)
	(segment
		(start 64.193674 -298.466764)
		(end 64.02959 -298.630848)
		(width 0.20066)
		(layer "F.Cu")
		(net "M_A_CPU1_SA_DQ<15>")
	)
	(segment
		(start 62.699646 -298.891706)
		(end 62.147958 -298.891706)
		(width 0.20066)
		(layer "F.Cu")
		(net "M_A_CPU1_SA_DQ<15>")
	)
	(segment
		(start 59.8424 -298.911518)
		(end 59.822842 -298.911518)
		(width 0.101854)
		(layer "F.Cu")
		(net "M_A_CPU1_SA_DQ<15>")
	)
	(segment
		(start 59.188604 -298.466764)
		(end 57.503314 -298.466764)
		(width 0.20066)
		(layer "F.Cu")
		(net "M_A_CPU1_SA_DQ<15>")
	)
	(segment
		(start 59.314842 -298.593002)
		(end 59.188604 -298.466764)
		(width 0.20066)
		(layer "F.Cu")
		(net "M_A_CPU1_SA_DQ<15>")
	)
	(segment
		(start 59.862212 -298.891706)
		(end 59.8424 -298.911518)
		(width 0.101854)
		(layer "F.Cu")
		(net "M_A_CPU1_SA_DQ<15>")
	)
	(segment
		(start 62.829694 -298.761658)
		(end 62.699646 -298.891706)
		(width 0.20066)
		(layer "F.Cu")
		(net "M_A_CPU1_SA_DQ<15>")
	)
	(segment
		(start 90.134694 -268.033754)
		(end 90.134694 -268.569694)
		(width 0.20066)
		(layer "F.Cu")
		(net "M_A_CPU1_SA_DQ<15>")
	)
	(segment
		(start 62.999366 -298.421044)
		(end 62.829694 -298.590716)
		(width 0.20066)
		(layer "F.Cu")
		(net "M_A_CPU1_SA_DQ<15>")
	)
	(segment
		(start 59.822842 -298.911518)
		(end 59.473846 -298.911518)
		(width 0.20066)
		(layer "F.Cu")
		(net "M_A_CPU1_SA_DQ<15>")
	)
	(segment
		(start 62.147958 -298.891706)
		(end 62.097412 -298.891706)
		(width 0.101854)
		(layer "F.Cu")
		(net "M_A_CPU1_SA_DQ<15>")
	)
	(segment
		(start 59.314842 -298.752514)
		(end 59.314842 -298.593002)
		(width 0.20066)
		(layer "F.Cu")
		(net "M_A_CPU1_SA_DQ<15>")
	)
	(segment
		(start 59.473846 -298.911518)
		(end 59.314842 -298.752514)
		(width 0.20066)
		(layer "F.Cu")
		(net "M_A_CPU1_SA_DQ<15>")
	)
	(segment
		(start 62.829694 -298.590716)
		(end 62.829694 -298.761658)
		(width 0.20066)
		(layer "F.Cu")
		(net "M_A_CPU1_SA_DQ<15>")
	)
	(segment
		(start 66.152014 -298.466764)
		(end 65.047114 -298.466764)
		(width 0.20066)
		(layer "F.Cu")
		(net "M_A_CPU1_SA_DQ<15>")
	)
	(segment
		(start 63.522098 -298.630848)
		(end 63.312294 -298.421044)
		(width 0.20066)
		(layer "F.Cu")
		(net "M_A_CPU1_SA_DQ<15>")
	)
	(segment
		(start 65.047114 -298.466764)
		(end 64.193674 -298.466764)
		(width 0.20066)
		(layer "F.Cu")
		(net "M_A_CPU1_SA_DQ<15>")
	)
	(segment
		(start 63.312294 -298.421044)
		(end 62.999366 -298.421044)
		(width 0.20066)
		(layer "F.Cu")
		(net "M_A_CPU1_SA_DQ<15>")
	)
	(segment
		(start 64.538098 -297.28287)
		(end 64.408558 -297.41241)
		(width 0.18288)
		(layer "In2.Cu")
		(net "M_A_CPU1_SA_DQ<15>")
	)
	(segment
		(start 65.824862 -297.28287)
		(end 64.538098 -297.28287)
		(width 0.18288)
		(layer "In2.Cu")
		(net "M_A_CPU1_SA_DQ<15>")
	)
	(segment
		(start 69.709792 -286.38246)
		(end 66.928238 -293.09695)
		(width 0.18288)
		(layer "In2.Cu")
		(net "M_A_CPU1_SA_DQ<15>")
	)
	(segment
		(start 65.151762 -295.57091)
		(end 66.017902 -296.43705)
		(width 0.18288)
		(layer "In2.Cu")
		(net "M_A_CPU1_SA_DQ<15>")
	)
	(segment
		(start 88.442546 -268.24559)
		(end 88.442292 -268.245336)
		(width 0.088646)
		(layer "In2.Cu")
		(net "M_A_CPU1_SA_DQ<15>")
	)
	(segment
		(start 74.014838 -282.077414)
		(end 69.709792 -286.38246)
		(width 0.18288)
		(layer "In2.Cu")
		(net "M_A_CPU1_SA_DQ<15>")
	)
	(segment
		(start 65.958974 -297.998896)
		(end 66.152014 -298.191936)
		(width 0.18288)
		(layer "In2.Cu")
		(net "M_A_CPU1_SA_DQ<15>")
	)
	(segment
		(start 64.408558 -297.80103)
		(end 64.606424 -297.998896)
		(width 0.18288)
		(layer "In2.Cu")
		(net "M_A_CPU1_SA_DQ<15>")
	)
	(segment
		(start 66.594228 -294.391588)
		(end 66.333878 -294.651938)
		(width 0.18288)
		(layer "In2.Cu")
		(net "M_A_CPU1_SA_DQ<15>")
	)
	(segment
		(start 84.703158 -268.913356)
		(end 84.599526 -269.016988)
		(width 0.088646)
		(layer "In2.Cu")
		(net "M_A_CPU1_SA_DQ<15>")
	)
	(segment
		(start 64.606424 -297.998896)
		(end 65.958974 -297.998896)
		(width 0.18288)
		(layer "In2.Cu")
		(net "M_A_CPU1_SA_DQ<15>")
	)
	(segment
		(start 66.70548 -293.245794)
		(end 66.594228 -293.357046)
		(width 0.18288)
		(layer "In2.Cu")
		(net "M_A_CPU1_SA_DQ<15>")
	)
	(segment
		(start 86.188296 -268.245336)
		(end 85.520276 -268.913356)
		(width 0.088646)
		(layer "In2.Cu")
		(net "M_A_CPU1_SA_DQ<15>")
	)
	(segment
		(start 64.052196 -294.844978)
		(end 64.052196 -295.325292)
		(width 0.18288)
		(layer "In2.Cu")
		(net "M_A_CPU1_SA_DQ<15>")
	)
	(segment
		(start 64.297814 -295.57091)
		(end 65.151762 -295.57091)
		(width 0.18288)
		(layer "In2.Cu")
		(net "M_A_CPU1_SA_DQ<15>")
	)
	(segment
		(start 90.134694 -268.569694)
		(end 89.410032 -268.877796)
		(width 0.088646)
		(layer "In2.Cu")
		(net "M_A_CPU1_SA_DQ<15>")
	)
	(segment
		(start 66.017902 -296.43705)
		(end 66.017902 -297.08983)
		(width 0.18288)
		(layer "In2.Cu")
		(net "M_A_CPU1_SA_DQ<15>")
	)
	(segment
		(start 89.410032 -268.877796)
		(end 89.382092 -268.894052)
		(width 0.088646)
		(layer "In2.Cu")
		(net "M_A_CPU1_SA_DQ<15>")
	)
	(segment
		(start 80.874362 -272.742152)
		(end 80.140048 -274.515072)
		(width 0.18288)
		(layer "In2.Cu")
		(net "M_A_CPU1_SA_DQ<15>")
	)
	(segment
		(start 88.861392 -268.740128)
		(end 88.611456 -268.454378)
		(width 0.088646)
		(layer "In2.Cu")
		(net "M_A_CPU1_SA_DQ<15>")
	)
	(segment
		(start 64.052196 -295.325292)
		(end 64.297814 -295.57091)
		(width 0.18288)
		(layer "In2.Cu")
		(net "M_A_CPU1_SA_DQ<15>")
	)
	(segment
		(start 89.007696 -268.894052)
		(end 89.007442 -268.893798)
		(width 0.088646)
		(layer "In2.Cu")
		(net "M_A_CPU1_SA_DQ<15>")
	)
	(segment
		(start 84.599526 -269.016988)
		(end 80.874362 -272.742152)
		(width 0.18288)
		(layer "In2.Cu")
		(net "M_A_CPU1_SA_DQ<15>")
	)
	(segment
		(start 75.031092 -279.624028)
		(end 74.014838 -282.077414)
		(width 0.18288)
		(layer "In2.Cu")
		(net "M_A_CPU1_SA_DQ<15>")
	)
	(segment
		(start 80.140048 -274.515072)
		(end 75.031092 -279.624028)
		(width 0.18288)
		(layer "In2.Cu")
		(net "M_A_CPU1_SA_DQ<15>")
	)
	(segment
		(start 66.152014 -298.191936)
		(end 66.152014 -298.466764)
		(width 0.18288)
		(layer "In2.Cu")
		(net "M_A_CPU1_SA_DQ<15>")
	)
	(segment
		(start 64.245236 -294.651938)
		(end 64.052196 -294.844978)
		(width 0.18288)
		(layer "In2.Cu")
		(net "M_A_CPU1_SA_DQ<15>")
	)
	(segment
		(start 66.333878 -294.651938)
		(end 64.245236 -294.651938)
		(width 0.18288)
		(layer "In2.Cu")
		(net "M_A_CPU1_SA_DQ<15>")
	)
	(segment
		(start 66.594228 -293.357046)
		(end 66.594228 -294.391588)
		(width 0.18288)
		(layer "In2.Cu")
		(net "M_A_CPU1_SA_DQ<15>")
	)
	(segment
		(start 85.520276 -268.913356)
		(end 84.703158 -268.913356)
		(width 0.088646)
		(layer "In2.Cu")
		(net "M_A_CPU1_SA_DQ<15>")
	)
	(segment
		(start 64.408558 -297.41241)
		(end 64.408558 -297.80103)
		(width 0.18288)
		(layer "In2.Cu")
		(net "M_A_CPU1_SA_DQ<15>")
	)
	(segment
		(start 66.928238 -293.09695)
		(end 66.70548 -293.245794)
		(width 0.18288)
		(layer "In2.Cu")
		(net "M_A_CPU1_SA_DQ<15>")
	)
	(segment
		(start 66.017902 -297.08983)
		(end 65.824862 -297.28287)
		(width 0.18288)
		(layer "In2.Cu")
		(net "M_A_CPU1_SA_DQ<15>")
	)
	(arc
		(start 88.067896 -268.245336)
		(mid 87.785194 -268.321112)
		(end 87.502492 -268.245336)
		(width 0.088646)
		(layer "In2.Cu")
		(net "M_A_CPU1_SA_DQ<15>")
	)
	(arc
		(start 89.007442 -268.893798)
		(mid 88.923272 -268.827548)
		(end 88.861392 -268.740128)
		(width 0.088646)
		(layer "In2.Cu")
		(net "M_A_CPU1_SA_DQ<15>")
	)
	(arc
		(start 88.442292 -268.245336)
		(mid 88.255094 -268.195193)
		(end 88.067896 -268.245336)
		(width 0.088646)
		(layer "In2.Cu")
		(net "M_A_CPU1_SA_DQ<15>")
	)
	(arc
		(start 87.128096 -268.245336)
		(mid 86.845394 -268.321112)
		(end 86.562692 -268.245336)
		(width 0.088646)
		(layer "In2.Cu")
		(net "M_A_CPU1_SA_DQ<15>")
	)
	(arc
		(start 87.502492 -268.245336)
		(mid 87.315294 -268.195193)
		(end 87.128096 -268.245336)
		(width 0.088646)
		(layer "In2.Cu")
		(net "M_A_CPU1_SA_DQ<15>")
	)
	(arc
		(start 86.562692 -268.245336)
		(mid 86.375494 -268.195193)
		(end 86.188296 -268.245336)
		(width 0.088646)
		(layer "In2.Cu")
		(net "M_A_CPU1_SA_DQ<15>")
	)
	(arc
		(start 89.382092 -268.894052)
		(mid 89.194894 -268.944229)
		(end 89.007696 -268.894052)
		(width 0.088646)
		(layer "In2.Cu")
		(net "M_A_CPU1_SA_DQ<15>")
	)
	(arc
		(start 88.611456 -268.454378)
		(mid 88.546354 -268.334337)
		(end 88.442546 -268.24559)
		(width 0.088646)
		(layer "In2.Cu")
		(net "M_A_CPU1_SA_DQ<15>")
	)
	(segment
		(start 59.102752 -299.856906)
		(end 59.102752 -300.039786)
		(width 0.20066)
		(layer "F.Cu")
		(net "M_A_CPU1_SA_DQ<14>")
	)
	(segment
		(start 59.822842 -299.725334)
		(end 59.234324 -299.725334)
		(width 0.20066)
		(layer "F.Cu")
		(net "M_A_CPU1_SA_DQ<14>")
	)
	(segment
		(start 59.887612 -299.74159)
		(end 59.871356 -299.725334)
		(width 0.101854)
		(layer "F.Cu")
		(net "M_A_CPU1_SA_DQ<14>")
	)
	(segment
		(start 62.136274 -299.74159)
		(end 59.887612 -299.74159)
		(width 0.1016)
		(layer "F.Cu")
		(net "M_A_CPU1_SA_DQ<14>")
	)
	(segment
		(start 65.047114 -300.166786)
		(end 63.577724 -300.166786)
		(width 0.20066)
		(layer "F.Cu")
		(net "M_A_CPU1_SA_DQ<14>")
	)
	(segment
		(start 63.125858 -300.345094)
		(end 62.913006 -300.132242)
		(width 0.20066)
		(layer "F.Cu")
		(net "M_A_CPU1_SA_DQ<14>")
	)
	(segment
		(start 63.577724 -300.166786)
		(end 63.399416 -300.345094)
		(width 0.20066)
		(layer "F.Cu")
		(net "M_A_CPU1_SA_DQ<14>")
	)
	(segment
		(start 59.234324 -299.725334)
		(end 59.102752 -299.856906)
		(width 0.20066)
		(layer "F.Cu")
		(net "M_A_CPU1_SA_DQ<14>")
	)
	(segment
		(start 59.871356 -299.725334)
		(end 59.822842 -299.725334)
		(width 0.101854)
		(layer "F.Cu")
		(net "M_A_CPU1_SA_DQ<14>")
	)
	(segment
		(start 62.737746 -299.74159)
		(end 62.147958 -299.74159)
		(width 0.20066)
		(layer "F.Cu")
		(net "M_A_CPU1_SA_DQ<14>")
	)
	(segment
		(start 90.604848 -268.84757)
		(end 90.604594 -268.847824)
		(width 0.20066)
		(layer "F.Cu")
		(net "M_A_CPU1_SA_DQ<14>")
	)
	(segment
		(start 58.975752 -300.166786)
		(end 57.503314 -300.166786)
		(width 0.20066)
		(layer "F.Cu")
		(net "M_A_CPU1_SA_DQ<14>")
	)
	(segment
		(start 63.399416 -300.345094)
		(end 63.125858 -300.345094)
		(width 0.20066)
		(layer "F.Cu")
		(net "M_A_CPU1_SA_DQ<14>")
	)
	(segment
		(start 59.102752 -300.039786)
		(end 58.975752 -300.166786)
		(width 0.20066)
		(layer "F.Cu")
		(net "M_A_CPU1_SA_DQ<14>")
	)
	(segment
		(start 62.913006 -300.132242)
		(end 62.913006 -299.91685)
		(width 0.20066)
		(layer "F.Cu")
		(net "M_A_CPU1_SA_DQ<14>")
	)
	(segment
		(start 90.604594 -268.847824)
		(end 90.604594 -269.38351)
		(width 0.20066)
		(layer "F.Cu")
		(net "M_A_CPU1_SA_DQ<14>")
	)
	(segment
		(start 62.147958 -299.74159)
		(end 62.136274 -299.74159)
		(width 0.101854)
		(layer "F.Cu")
		(net "M_A_CPU1_SA_DQ<14>")
	)
	(segment
		(start 62.913006 -299.91685)
		(end 62.737746 -299.74159)
		(width 0.20066)
		(layer "F.Cu")
		(net "M_A_CPU1_SA_DQ<14>")
	)
	(segment
		(start 66.152014 -300.166786)
		(end 65.047114 -300.166786)
		(width 0.20066)
		(layer "F.Cu")
		(net "M_A_CPU1_SA_DQ<14>")
	)
	(segment
		(start 69.85 -289.088322)
		(end 69.72808 -289.3822)
		(width 0.18288)
		(layer "In2.Cu")
		(net "M_A_CPU1_SA_DQ<14>")
	)
	(segment
		(start 68.667884 -291.437568)
		(end 68.772024 -291.689282)
		(width 0.18288)
		(layer "In2.Cu")
		(net "M_A_CPU1_SA_DQ<14>")
	)
	(segment
		(start 81.168494 -272.936716)
		(end 80.27035 -275.10359)
		(width 0.18288)
		(layer "In2.Cu")
		(net "M_A_CPU1_SA_DQ<14>")
	)
	(segment
		(start 69.417946 -288.49193)
		(end 69.522594 -288.743898)
		(width 0.18288)
		(layer "In2.Cu")
		(net "M_A_CPU1_SA_DQ<14>")
	)
	(segment
		(start 85.60689 -269.76705)
		(end 85.28431 -269.44447)
		(width 0.088646)
		(layer "In2.Cu")
		(net "M_A_CPU1_SA_DQ<14>")
	)
	(segment
		(start 70.1929 -286.617918)
		(end 70.193408 -286.617918)
		(width 0.18288)
		(layer "In2.Cu")
		(net "M_A_CPU1_SA_DQ<14>")
	)
	(segment
		(start 88.537796 -269.059152)
		(end 88.15832 -268.93139)
		(width 0.088646)
		(layer "In2.Cu")
		(net "M_A_CPU1_SA_DQ<14>")
	)
	(segment
		(start 80.27035 -275.10359)
		(end 75.461876 -279.912064)
		(width 0.18288)
		(layer "In2.Cu")
		(net "M_A_CPU1_SA_DQ<14>")
	)
	(segment
		(start 85.891116 -269.76705)
		(end 85.60689 -269.76705)
		(width 0.088646)
		(layer "In2.Cu")
		(net "M_A_CPU1_SA_DQ<14>")
	)
	(segment
		(start 90.604594 -269.38351)
		(end 89.879932 -269.075408)
		(width 0.088646)
		(layer "In2.Cu")
		(net "M_A_CPU1_SA_DQ<14>")
	)
	(segment
		(start 67.636136 -293.295578)
		(end 67.383914 -293.400226)
		(width 0.18288)
		(layer "In2.Cu")
		(net "M_A_CPU1_SA_DQ<14>")
	)
	(segment
		(start 66.954908 -294.7543)
		(end 66.660268 -295.465246)
		(width 0.18288)
		(layer "In2.Cu")
		(net "M_A_CPU1_SA_DQ<14>")
	)
	(segment
		(start 67.32016 -294.688514)
		(end 67.21729 -294.645842)
		(width 0.18288)
		(layer "In2.Cu")
		(net "M_A_CPU1_SA_DQ<14>")
	)
	(segment
		(start 67.589908 -294.038528)
		(end 67.694048 -294.290242)
		(width 0.18288)
		(layer "In2.Cu")
		(net "M_A_CPU1_SA_DQ<14>")
	)
	(segment
		(start 68.46189 -290.799266)
		(end 68.33997 -291.09289)
		(width 0.18288)
		(layer "In2.Cu")
		(net "M_A_CPU1_SA_DQ<14>")
	)
	(segment
		(start 68.33997 -291.09289)
		(end 68.444618 -291.344858)
		(width 0.18288)
		(layer "In2.Cu")
		(net "M_A_CPU1_SA_DQ<14>")
	)
	(segment
		(start 70.0151 -288.186114)
		(end 69.792088 -288.093658)
		(width 0.18288)
		(layer "In2.Cu")
		(net "M_A_CPU1_SA_DQ<14>")
	)
	(segment
		(start 74.445622 -282.365196)
		(end 70.1929 -286.617918)
		(width 0.18288)
		(layer "In2.Cu")
		(net "M_A_CPU1_SA_DQ<14>")
	)
	(segment
		(start 66.660268 -295.465246)
		(end 66.660268 -299.658532)
		(width 0.18288)
		(layer "In2.Cu")
		(net "M_A_CPU1_SA_DQ<14>")
	)
	(segment
		(start 69.792088 -288.093658)
		(end 69.539866 -288.198306)
		(width 0.18288)
		(layer "In2.Cu")
		(net "M_A_CPU1_SA_DQ<14>")
	)
	(segment
		(start 70.267068 -288.08172)
		(end 70.0151 -288.186114)
		(width 0.18288)
		(layer "In2.Cu")
		(net "M_A_CPU1_SA_DQ<14>")
	)
	(segment
		(start 68.111116 -293.28364)
		(end 67.859148 -293.388034)
		(width 0.18288)
		(layer "In2.Cu")
		(net "M_A_CPU1_SA_DQ<14>")
	)
	(segment
		(start 67.21729 -294.645842)
		(end 66.954908 -294.7543)
		(width 0.18288)
		(layer "In2.Cu")
		(net "M_A_CPU1_SA_DQ<14>")
	)
	(segment
		(start 84.66074 -269.44447)
		(end 81.168494 -272.936716)
		(width 0.18288)
		(layer "In2.Cu")
		(net "M_A_CPU1_SA_DQ<14>")
	)
	(segment
		(start 68.398136 -292.087554)
		(end 68.175124 -291.995098)
		(width 0.18288)
		(layer "In2.Cu")
		(net "M_A_CPU1_SA_DQ<14>")
	)
	(segment
		(start 69.189092 -290.68268)
		(end 68.937124 -290.787074)
		(width 0.18288)
		(layer "In2.Cu")
		(net "M_A_CPU1_SA_DQ<14>")
	)
	(segment
		(start 66.660268 -299.658532)
		(end 66.152014 -300.166786)
		(width 0.18288)
		(layer "In2.Cu")
		(net "M_A_CPU1_SA_DQ<14>")
	)
	(segment
		(start 69.956934 -287.19145)
		(end 70.061582 -287.443418)
		(width 0.18288)
		(layer "In2.Cu")
		(net "M_A_CPU1_SA_DQ<14>")
	)
	(segment
		(start 89.879932 -269.075408)
		(end 89.851992 -269.059152)
		(width 0.088646)
		(layer "In2.Cu")
		(net "M_A_CPU1_SA_DQ<14>")
	)
	(segment
		(start 70.284848 -287.536128)
		(end 70.388988 -287.787842)
		(width 0.18288)
		(layer "In2.Cu")
		(net "M_A_CPU1_SA_DQ<14>")
	)
	(segment
		(start 68.175124 -291.995098)
		(end 67.922902 -292.099746)
		(width 0.18288)
		(layer "In2.Cu")
		(net "M_A_CPU1_SA_DQ<14>")
	)
	(segment
		(start 69.522594 -288.743898)
		(end 69.74586 -288.836608)
		(width 0.18288)
		(layer "In2.Cu")
		(net "M_A_CPU1_SA_DQ<14>")
	)
	(segment
		(start 84.875878 -269.44447)
		(end 84.66074 -269.44447)
		(width 0.18288)
		(layer "In2.Cu")
		(net "M_A_CPU1_SA_DQ<14>")
	)
	(segment
		(start 67.366642 -293.945818)
		(end 67.589908 -294.038528)
		(width 0.18288)
		(layer "In2.Cu")
		(net "M_A_CPU1_SA_DQ<14>")
	)
	(segment
		(start 67.383914 -293.400226)
		(end 67.261994 -293.69385)
		(width 0.18288)
		(layer "In2.Cu")
		(net "M_A_CPU1_SA_DQ<14>")
	)
	(segment
		(start 69.206872 -290.137088)
		(end 69.311012 -290.388802)
		(width 0.18288)
		(layer "In2.Cu")
		(net "M_A_CPU1_SA_DQ<14>")
	)
	(segment
		(start 68.650104 -291.98316)
		(end 68.398136 -292.087554)
		(width 0.18288)
		(layer "In2.Cu")
		(net "M_A_CPU1_SA_DQ<14>")
	)
	(segment
		(start 70.061582 -287.443418)
		(end 70.284848 -287.536128)
		(width 0.18288)
		(layer "In2.Cu")
		(net "M_A_CPU1_SA_DQ<14>")
	)
	(segment
		(start 67.90563 -292.645338)
		(end 68.128896 -292.738048)
		(width 0.18288)
		(layer "In2.Cu")
		(net "M_A_CPU1_SA_DQ<14>")
	)
	(segment
		(start 69.72808 -289.3822)
		(end 69.476112 -289.486594)
		(width 0.18288)
		(layer "In2.Cu")
		(net "M_A_CPU1_SA_DQ<14>")
	)
	(segment
		(start 85.28431 -269.44447)
		(end 84.875878 -269.44447)
		(width 0.088646)
		(layer "In2.Cu")
		(net "M_A_CPU1_SA_DQ<14>")
	)
	(segment
		(start 68.233036 -292.989762)
		(end 68.111116 -293.28364)
		(width 0.18288)
		(layer "In2.Cu")
		(net "M_A_CPU1_SA_DQ<14>")
	)
	(segment
		(start 67.800982 -292.39337)
		(end 67.90563 -292.645338)
		(width 0.18288)
		(layer "In2.Cu")
		(net "M_A_CPU1_SA_DQ<14>")
	)
	(segment
		(start 86.101682 -269.702788)
		(end 86.04631 -269.734538)
		(width 0.088646)
		(layer "In2.Cu")
		(net "M_A_CPU1_SA_DQ<14>")
	)
	(segment
		(start 70.193916 -286.618426)
		(end 69.956934 -287.19145)
		(width 0.18288)
		(layer "In2.Cu")
		(net "M_A_CPU1_SA_DQ<14>")
	)
	(segment
		(start 67.922902 -292.099746)
		(end 67.800982 -292.39337)
		(width 0.18288)
		(layer "In2.Cu")
		(net "M_A_CPU1_SA_DQ<14>")
	)
	(segment
		(start 86.280244 -269.373604)
		(end 86.280244 -269.38351)
		(width 0.088646)
		(layer "In2.Cu")
		(net "M_A_CPU1_SA_DQ<14>")
	)
	(segment
		(start 75.461876 -279.912064)
		(end 74.445622 -282.365196)
		(width 0.18288)
		(layer "In2.Cu")
		(net "M_A_CPU1_SA_DQ<14>")
	)
	(segment
		(start 67.859148 -293.388034)
		(end 67.636136 -293.295578)
		(width 0.18288)
		(layer "In2.Cu")
		(net "M_A_CPU1_SA_DQ<14>")
	)
	(segment
		(start 70.193408 -286.617918)
		(end 70.193916 -286.618426)
		(width 0.18288)
		(layer "In2.Cu")
		(net "M_A_CPU1_SA_DQ<14>")
	)
	(segment
		(start 67.261994 -293.69385)
		(end 67.366642 -293.945818)
		(width 0.18288)
		(layer "In2.Cu")
		(net "M_A_CPU1_SA_DQ<14>")
	)
	(segment
		(start 68.772024 -291.689282)
		(end 68.650104 -291.98316)
		(width 0.18288)
		(layer "In2.Cu")
		(net "M_A_CPU1_SA_DQ<14>")
	)
	(segment
		(start 68.714112 -290.694618)
		(end 68.46189 -290.799266)
		(width 0.18288)
		(layer "In2.Cu")
		(net "M_A_CPU1_SA_DQ<14>")
	)
	(segment
		(start 68.983606 -290.044378)
		(end 69.206872 -290.137088)
		(width 0.18288)
		(layer "In2.Cu")
		(net "M_A_CPU1_SA_DQ<14>")
	)
	(segment
		(start 68.878958 -289.79241)
		(end 68.983606 -290.044378)
		(width 0.18288)
		(layer "In2.Cu")
		(net "M_A_CPU1_SA_DQ<14>")
	)
	(segment
		(start 67.572128 -294.58412)
		(end 67.32016 -294.688514)
		(width 0.18288)
		(layer "In2.Cu")
		(net "M_A_CPU1_SA_DQ<14>")
	)
	(segment
		(start 69.311012 -290.388802)
		(end 69.189092 -290.68268)
		(width 0.18288)
		(layer "In2.Cu")
		(net "M_A_CPU1_SA_DQ<14>")
	)
	(segment
		(start 69.74586 -288.836608)
		(end 69.85 -289.088322)
		(width 0.18288)
		(layer "In2.Cu")
		(net "M_A_CPU1_SA_DQ<14>")
	)
	(segment
		(start 67.694048 -294.290242)
		(end 67.572128 -294.58412)
		(width 0.18288)
		(layer "In2.Cu")
		(net "M_A_CPU1_SA_DQ<14>")
	)
	(segment
		(start 69.2531 -289.394138)
		(end 69.000878 -289.498786)
		(width 0.18288)
		(layer "In2.Cu")
		(net "M_A_CPU1_SA_DQ<14>")
	)
	(segment
		(start 69.539866 -288.198306)
		(end 69.417946 -288.49193)
		(width 0.18288)
		(layer "In2.Cu")
		(net "M_A_CPU1_SA_DQ<14>")
	)
	(segment
		(start 68.937124 -290.787074)
		(end 68.714112 -290.694618)
		(width 0.18288)
		(layer "In2.Cu")
		(net "M_A_CPU1_SA_DQ<14>")
	)
	(segment
		(start 69.000878 -289.498786)
		(end 68.878958 -289.79241)
		(width 0.18288)
		(layer "In2.Cu")
		(net "M_A_CPU1_SA_DQ<14>")
	)
	(segment
		(start 70.388988 -287.787842)
		(end 70.267068 -288.08172)
		(width 0.18288)
		(layer "In2.Cu")
		(net "M_A_CPU1_SA_DQ<14>")
	)
	(segment
		(start 68.444618 -291.344858)
		(end 68.667884 -291.437568)
		(width 0.18288)
		(layer "In2.Cu")
		(net "M_A_CPU1_SA_DQ<14>")
	)
	(segment
		(start 69.476112 -289.486594)
		(end 69.2531 -289.394138)
		(width 0.18288)
		(layer "In2.Cu")
		(net "M_A_CPU1_SA_DQ<14>")
	)
	(segment
		(start 68.128896 -292.738048)
		(end 68.233036 -292.989762)
		(width 0.18288)
		(layer "In2.Cu")
		(net "M_A_CPU1_SA_DQ<14>")
	)
	(arc
		(start 87.128096 -268.894052)
		(mid 86.845394 -268.818276)
		(end 86.562692 -268.894052)
		(width 0.088646)
		(layer "In2.Cu")
		(net "M_A_CPU1_SA_DQ<14>")
	)
	(arc
		(start 87.502492 -268.894052)
		(mid 87.315294 -268.944195)
		(end 87.128096 -268.894052)
		(width 0.088646)
		(layer "In2.Cu")
		(net "M_A_CPU1_SA_DQ<14>")
	)
	(arc
		(start 86.04631 -269.734538)
		(mid 85.971271 -269.763009)
		(end 85.891116 -269.76705)
		(width 0.088646)
		(layer "In2.Cu")
		(net "M_A_CPU1_SA_DQ<14>")
	)
	(arc
		(start 89.477596 -269.059152)
		(mid 89.194894 -269.134894)
		(end 88.912192 -269.059152)
		(width 0.088646)
		(layer "In2.Cu")
		(net "M_A_CPU1_SA_DQ<14>")
	)
	(arc
		(start 89.851992 -269.059152)
		(mid 89.664794 -269.009009)
		(end 89.477596 -269.059152)
		(width 0.088646)
		(layer "In2.Cu")
		(net "M_A_CPU1_SA_DQ<14>")
	)
	(arc
		(start 86.562692 -268.894052)
		(mid 86.358357 -269.096657)
		(end 86.280244 -269.373604)
		(width 0.088646)
		(layer "In2.Cu")
		(net "M_A_CPU1_SA_DQ<14>")
	)
	(arc
		(start 88.15832 -268.93139)
		(mid 88.111888 -268.915678)
		(end 88.067896 -268.894052)
		(width 0.088646)
		(layer "In2.Cu")
		(net "M_A_CPU1_SA_DQ<14>")
	)
	(arc
		(start 88.912192 -269.059152)
		(mid 88.724994 -269.008975)
		(end 88.537796 -269.059152)
		(width 0.088646)
		(layer "In2.Cu")
		(net "M_A_CPU1_SA_DQ<14>")
	)
	(arc
		(start 88.067896 -268.894052)
		(mid 87.785194 -268.818276)
		(end 87.502492 -268.894052)
		(width 0.088646)
		(layer "In2.Cu")
		(net "M_A_CPU1_SA_DQ<14>")
	)
	(arc
		(start 86.280244 -269.38351)
		(mid 86.232565 -269.56641)
		(end 86.101682 -269.702788)
		(width 0.088646)
		(layer "In2.Cu")
		(net "M_A_CPU1_SA_DQ<14>")
	)
	(segment
		(start 56.37911 -298.870878)
		(end 55.072788 -298.870878)
		(width 0.20066)
		(layer "F.Cu")
		(net "M_A_CPU1_SA_DQ<13>")
	)
	(segment
		(start 54.897528 -299.334174)
		(end 54.66334 -299.568362)
		(width 0.20066)
		(layer "F.Cu")
		(net "M_A_CPU1_SA_DQ<13>")
	)
	(segment
		(start 58.704226 -298.891706)
		(end 58.643012 -298.891706)
		(width 0.101854)
		(layer "F.Cu")
		(net "M_A_CPU1_SA_DQ<13>")
	)
	(segment
		(start 56.381142 -298.870878)
		(end 56.37911 -298.870878)
		(width 0.101854)
		(layer "F.Cu")
		(net "M_A_CPU1_SA_DQ<13>")
	)
	(segment
		(start 62.051946 -299.316648)
		(end 60.947046 -299.316648)
		(width 0.20066)
		(layer "F.Cu")
		(net "M_A_CPU1_SA_DQ<13>")
	)
	(segment
		(start 55.072788 -298.870878)
		(end 54.897528 -299.046138)
		(width 0.20066)
		(layer "F.Cu")
		(net "M_A_CPU1_SA_DQ<13>")
	)
	(segment
		(start 54.279292 -299.568362)
		(end 54.027324 -299.316394)
		(width 0.20066)
		(layer "F.Cu")
		(net "M_A_CPU1_SA_DQ<13>")
	)
	(segment
		(start 54.02707 -299.316648)
		(end 53.403246 -299.316648)
		(width 0.20066)
		(layer "F.Cu")
		(net "M_A_CPU1_SA_DQ<13>")
	)
	(segment
		(start 56.40197 -298.891706)
		(end 56.381142 -298.870878)
		(width 0.101854)
		(layer "F.Cu")
		(net "M_A_CPU1_SA_DQ<13>")
	)
	(segment
		(start 54.897528 -299.046138)
		(end 54.897528 -299.334174)
		(width 0.20066)
		(layer "F.Cu")
		(net "M_A_CPU1_SA_DQ<13>")
	)
	(segment
		(start 59.273694 -299.316648)
		(end 58.848752 -298.891706)
		(width 0.20066)
		(layer "F.Cu")
		(net "M_A_CPU1_SA_DQ<13>")
	)
	(segment
		(start 58.848752 -298.891706)
		(end 58.704226 -298.891706)
		(width 0.20066)
		(layer "F.Cu")
		(net "M_A_CPU1_SA_DQ<13>")
	)
	(segment
		(start 58.643012 -298.891706)
		(end 56.433212 -298.891706)
		(width 0.1016)
		(layer "F.Cu")
		(net "M_A_CPU1_SA_DQ<13>")
	)
	(segment
		(start 54.027324 -299.316394)
		(end 54.02707 -299.316648)
		(width 0.20066)
		(layer "F.Cu")
		(net "M_A_CPU1_SA_DQ<13>")
	)
	(segment
		(start 60.947046 -299.316648)
		(end 59.273694 -299.316648)
		(width 0.20066)
		(layer "F.Cu")
		(net "M_A_CPU1_SA_DQ<13>")
	)
	(segment
		(start 56.433212 -298.891706)
		(end 56.40197 -298.891706)
		(width 0.101854)
		(layer "F.Cu")
		(net "M_A_CPU1_SA_DQ<13>")
	)
	(segment
		(start 54.66334 -299.568362)
		(end 54.279292 -299.568362)
		(width 0.20066)
		(layer "F.Cu")
		(net "M_A_CPU1_SA_DQ<13>")
	)
	(segment
		(start 89.194894 -268.033754)
		(end 89.194894 -268.569694)
		(width 0.20066)
		(layer "F.Cu")
		(net "M_A_CPU1_SA_DQ<13>")
	)
	(segment
		(start 65.8749 -293.784782)
		(end 63.648844 -293.784782)
		(width 0.18288)
		(layer "In2.Cu")
		(net "M_A_CPU1_SA_DQ<13>")
	)
	(segment
		(start 63.262764 -295.594532)
		(end 62.412118 -295.594532)
		(width 0.18288)
		(layer "In2.Cu")
		(net "M_A_CPU1_SA_DQ<13>")
	)
	(segment
		(start 66.520568 -292.618414)
		(end 66.06794 -293.071042)
		(width 0.18288)
		(layer "In2.Cu")
		(net "M_A_CPU1_SA_DQ<13>")
	)
	(segment
		(start 62.586108 -298.235116)
		(end 62.586108 -298.798742)
		(width 0.18288)
		(layer "In2.Cu")
		(net "M_A_CPU1_SA_DQ<13>")
	)
	(segment
		(start 63.417958 -297.229784)
		(end 62.396878 -297.229784)
		(width 0.18288)
		(layer "In2.Cu")
		(net "M_A_CPU1_SA_DQ<13>")
	)
	(segment
		(start 63.455804 -295.401492)
		(end 63.262764 -295.594532)
		(width 0.18288)
		(layer "In2.Cu")
		(net "M_A_CPU1_SA_DQ<13>")
	)
	(segment
		(start 84.355178 -268.77264)
		(end 80.577944 -272.549874)
		(width 0.18288)
		(layer "In2.Cu")
		(net "M_A_CPU1_SA_DQ<13>")
	)
	(segment
		(start 62.203838 -297.852846)
		(end 62.586108 -298.235116)
		(width 0.18288)
		(layer "In2.Cu")
		(net "M_A_CPU1_SA_DQ<13>")
	)
	(segment
		(start 73.584308 -281.789124)
		(end 69.182488 -286.190944)
		(width 0.18288)
		(layer "In2.Cu")
		(net "M_A_CPU1_SA_DQ<13>")
	)
	(segment
		(start 88.56599 -268.096492)
		(end 88.537796 -268.080236)
		(width 0.088646)
		(layer "In2.Cu")
		(net "M_A_CPU1_SA_DQ<13>")
	)
	(segment
		(start 80.00619 -273.93011)
		(end 74.600562 -279.335738)
		(width 0.18288)
		(layer "In2.Cu")
		(net "M_A_CPU1_SA_DQ<13>")
	)
	(segment
		(start 66.06794 -293.591742)
		(end 65.8749 -293.784782)
		(width 0.18288)
		(layer "In2.Cu")
		(net "M_A_CPU1_SA_DQ<13>")
	)
	(segment
		(start 63.417958 -296.298112)
		(end 63.610998 -296.491152)
		(width 0.18288)
		(layer "In2.Cu")
		(net "M_A_CPU1_SA_DQ<13>")
	)
	(segment
		(start 80.577944 -272.549874)
		(end 80.00619 -273.93011)
		(width 0.18288)
		(layer "In2.Cu")
		(net "M_A_CPU1_SA_DQ<13>")
	)
	(segment
		(start 66.06794 -293.071042)
		(end 66.06794 -293.591742)
		(width 0.18288)
		(layer "In2.Cu")
		(net "M_A_CPU1_SA_DQ<13>")
	)
	(segment
		(start 85.522054 -268.600682)
		(end 84.527136 -268.600682)
		(width 0.088646)
		(layer "In2.Cu")
		(net "M_A_CPU1_SA_DQ<13>")
	)
	(segment
		(start 62.219078 -295.787572)
		(end 62.219078 -296.105072)
		(width 0.18288)
		(layer "In2.Cu")
		(net "M_A_CPU1_SA_DQ<13>")
	)
	(segment
		(start 62.068202 -299.316648)
		(end 62.051946 -299.316648)
		(width 0.18288)
		(layer "In2.Cu")
		(net "M_A_CPU1_SA_DQ<13>")
	)
	(segment
		(start 84.527136 -268.600682)
		(end 84.355178 -268.77264)
		(width 0.088646)
		(layer "In2.Cu")
		(net "M_A_CPU1_SA_DQ<13>")
	)
	(segment
		(start 63.610998 -296.491152)
		(end 63.610998 -297.036744)
		(width 0.18288)
		(layer "In2.Cu")
		(net "M_A_CPU1_SA_DQ<13>")
	)
	(segment
		(start 62.203838 -297.422824)
		(end 62.203838 -297.852846)
		(width 0.18288)
		(layer "In2.Cu")
		(net "M_A_CPU1_SA_DQ<13>")
	)
	(segment
		(start 62.219078 -296.105072)
		(end 62.412118 -296.298112)
		(width 0.18288)
		(layer "In2.Cu")
		(net "M_A_CPU1_SA_DQ<13>")
	)
	(segment
		(start 85.8774 -268.245336)
		(end 85.522054 -268.600682)
		(width 0.088646)
		(layer "In2.Cu")
		(net "M_A_CPU1_SA_DQ<13>")
	)
	(segment
		(start 63.455804 -293.977822)
		(end 63.455804 -295.401492)
		(width 0.18288)
		(layer "In2.Cu")
		(net "M_A_CPU1_SA_DQ<13>")
	)
	(segment
		(start 89.194894 -268.569694)
		(end 88.56599 -268.096492)
		(width 0.088646)
		(layer "In2.Cu")
		(net "M_A_CPU1_SA_DQ<13>")
	)
	(segment
		(start 74.600562 -279.335738)
		(end 73.584308 -281.789124)
		(width 0.18288)
		(layer "In2.Cu")
		(net "M_A_CPU1_SA_DQ<13>")
	)
	(segment
		(start 62.586108 -298.798742)
		(end 62.068202 -299.316648)
		(width 0.18288)
		(layer "In2.Cu")
		(net "M_A_CPU1_SA_DQ<13>")
	)
	(segment
		(start 62.412118 -296.298112)
		(end 63.417958 -296.298112)
		(width 0.18288)
		(layer "In2.Cu")
		(net "M_A_CPU1_SA_DQ<13>")
	)
	(segment
		(start 63.610998 -297.036744)
		(end 63.417958 -297.229784)
		(width 0.18288)
		(layer "In2.Cu")
		(net "M_A_CPU1_SA_DQ<13>")
	)
	(segment
		(start 62.396878 -297.229784)
		(end 62.203838 -297.422824)
		(width 0.18288)
		(layer "In2.Cu")
		(net "M_A_CPU1_SA_DQ<13>")
	)
	(segment
		(start 62.412118 -295.594532)
		(end 62.219078 -295.787572)
		(width 0.18288)
		(layer "In2.Cu")
		(net "M_A_CPU1_SA_DQ<13>")
	)
	(segment
		(start 63.648844 -293.784782)
		(end 63.455804 -293.977822)
		(width 0.18288)
		(layer "In2.Cu")
		(net "M_A_CPU1_SA_DQ<13>")
	)
	(segment
		(start 69.182488 -286.190944)
		(end 66.520568 -292.618414)
		(width 0.18288)
		(layer "In2.Cu")
		(net "M_A_CPU1_SA_DQ<13>")
	)
	(arc
		(start 88.537796 -268.080236)
		(mid 88.255094 -268.004494)
		(end 87.972392 -268.080236)
		(width 0.088646)
		(layer "In2.Cu")
		(net "M_A_CPU1_SA_DQ<13>")
	)
	(arc
		(start 86.658196 -268.080236)
		(mid 86.375494 -268.00446)
		(end 86.092792 -268.080236)
		(width 0.088646)
		(layer "In2.Cu")
		(net "M_A_CPU1_SA_DQ<13>")
	)
	(arc
		(start 87.972392 -268.080236)
		(mid 87.785194 -268.130379)
		(end 87.597996 -268.080236)
		(width 0.088646)
		(layer "In2.Cu")
		(net "M_A_CPU1_SA_DQ<13>")
	)
	(arc
		(start 87.032592 -268.080236)
		(mid 86.845394 -268.130379)
		(end 86.658196 -268.080236)
		(width 0.088646)
		(layer "In2.Cu")
		(net "M_A_CPU1_SA_DQ<13>")
	)
	(arc
		(start 87.597996 -268.080236)
		(mid 87.315294 -268.00446)
		(end 87.032592 -268.080236)
		(width 0.088646)
		(layer "In2.Cu")
		(net "M_A_CPU1_SA_DQ<13>")
	)
	(arc
		(start 86.092792 -268.080236)
		(mid 85.979677 -268.155715)
		(end 85.8774 -268.245336)
		(width 0.088646)
		(layer "In2.Cu")
		(net "M_A_CPU1_SA_DQ<13>")
	)
	(segment
		(start 55.072788 -300.5709)
		(end 54.897528 -300.74616)
		(width 0.20066)
		(layer "F.Cu")
		(net "M_A_CPU1_SA_DQ<12>")
	)
	(segment
		(start 58.903616 -300.591728)
		(end 58.704226 -300.591728)
		(width 0.20066)
		(layer "F.Cu")
		(net "M_A_CPU1_SA_DQ<12>")
	)
	(segment
		(start 58.668412 -300.591728)
		(end 56.433212 -300.591728)
		(width 0.1016)
		(layer "F.Cu")
		(net "M_A_CPU1_SA_DQ<12>")
	)
	(segment
		(start 88.724994 -268.847824)
		(end 88.724994 -269.38351)
		(width 0.20066)
		(layer "F.Cu")
		(net "M_A_CPU1_SA_DQ<12>")
	)
	(segment
		(start 60.04179 -301.01667)
		(end 59.850528 -300.825408)
		(width 0.20066)
		(layer "F.Cu")
		(net "M_A_CPU1_SA_DQ<12>")
	)
	(segment
		(start 54.897528 -301.034196)
		(end 54.66334 -301.268384)
		(width 0.20066)
		(layer "F.Cu")
		(net "M_A_CPU1_SA_DQ<12>")
	)
	(segment
		(start 62.051946 -301.01667)
		(end 60.947046 -301.01667)
		(width 0.20066)
		(layer "F.Cu")
		(net "M_A_CPU1_SA_DQ<12>")
	)
	(segment
		(start 60.947046 -301.01667)
		(end 60.04179 -301.01667)
		(width 0.20066)
		(layer "F.Cu")
		(net "M_A_CPU1_SA_DQ<12>")
	)
	(segment
		(start 59.137296 -300.825408)
		(end 58.903616 -300.591728)
		(width 0.20066)
		(layer "F.Cu")
		(net "M_A_CPU1_SA_DQ<12>")
	)
	(segment
		(start 59.850528 -300.825408)
		(end 59.137296 -300.825408)
		(width 0.20066)
		(layer "F.Cu")
		(net "M_A_CPU1_SA_DQ<12>")
	)
	(segment
		(start 54.66334 -301.268384)
		(end 54.279292 -301.268384)
		(width 0.20066)
		(layer "F.Cu")
		(net "M_A_CPU1_SA_DQ<12>")
	)
	(segment
		(start 54.02707 -301.01667)
		(end 53.403246 -301.01667)
		(width 0.20066)
		(layer "F.Cu")
		(net "M_A_CPU1_SA_DQ<12>")
	)
	(segment
		(start 54.279292 -301.268384)
		(end 54.027324 -301.016416)
		(width 0.20066)
		(layer "F.Cu")
		(net "M_A_CPU1_SA_DQ<12>")
	)
	(segment
		(start 56.37911 -300.5709)
		(end 55.072788 -300.5709)
		(width 0.20066)
		(layer "F.Cu")
		(net "M_A_CPU1_SA_DQ<12>")
	)
	(segment
		(start 54.027324 -301.016416)
		(end 54.02707 -301.01667)
		(width 0.20066)
		(layer "F.Cu")
		(net "M_A_CPU1_SA_DQ<12>")
	)
	(segment
		(start 56.433212 -300.591728)
		(end 56.412384 -300.5709)
		(width 0.101854)
		(layer "F.Cu")
		(net "M_A_CPU1_SA_DQ<12>")
	)
	(segment
		(start 88.725248 -268.84757)
		(end 88.724994 -268.847824)
		(width 0.20066)
		(layer "F.Cu")
		(net "M_A_CPU1_SA_DQ<12>")
	)
	(segment
		(start 56.412384 -300.5709)
		(end 56.37911 -300.5709)
		(width 0.101854)
		(layer "F.Cu")
		(net "M_A_CPU1_SA_DQ<12>")
	)
	(segment
		(start 58.704226 -300.591728)
		(end 58.668412 -300.591728)
		(width 0.101854)
		(layer "F.Cu")
		(net "M_A_CPU1_SA_DQ<12>")
	)
	(segment
		(start 54.897528 -300.74616)
		(end 54.897528 -301.034196)
		(width 0.20066)
		(layer "F.Cu")
		(net "M_A_CPU1_SA_DQ<12>")
	)
	(segment
		(start 64.386714 -301.178976)
		(end 64.386714 -300.785022)
		(width 0.18288)
		(layer "In2.Cu")
		(net "M_A_CPU1_SA_DQ<12>")
	)
	(segment
		(start 63.394082 -301.625762)
		(end 63.201042 -301.818802)
		(width 0.18288)
		(layer "In2.Cu")
		(net "M_A_CPU1_SA_DQ<12>")
	)
	(segment
		(start 67.168268 -295.731184)
		(end 67.168268 -299.809408)
		(width 0.18288)
		(layer "In2.Cu")
		(net "M_A_CPU1_SA_DQ<12>")
	)
	(segment
		(start 71.784972 -285.744666)
		(end 67.921886 -295.073578)
		(width 0.18288)
		(layer "In2.Cu")
		(net "M_A_CPU1_SA_DQ<12>")
	)
	(segment
		(start 74.876152 -282.653486)
		(end 71.784972 -285.744666)
		(width 0.18288)
		(layer "In2.Cu")
		(net "M_A_CPU1_SA_DQ<12>")
	)
	(segment
		(start 84.166202 -270.427704)
		(end 81.462626 -273.13128)
		(width 0.18288)
		(layer "In2.Cu")
		(net "M_A_CPU1_SA_DQ<12>")
	)
	(segment
		(start 66.991484 -300.236128)
		(end 66.4591 -300.591728)
		(width 0.18288)
		(layer "In2.Cu")
		(net "M_A_CPU1_SA_DQ<12>")
	)
	(segment
		(start 66.4591 -300.591728)
		(end 65.283588 -300.591728)
		(width 0.18288)
		(layer "In2.Cu")
		(net "M_A_CPU1_SA_DQ<12>")
	)
	(segment
		(start 65.090294 -301.178976)
		(end 64.897254 -301.372016)
		(width 0.18288)
		(layer "In2.Cu")
		(net "M_A_CPU1_SA_DQ<12>")
	)
	(segment
		(start 62.497462 -301.01667)
		(end 62.051946 -301.01667)
		(width 0.18288)
		(layer "In2.Cu")
		(net "M_A_CPU1_SA_DQ<12>")
	)
	(segment
		(start 84.270596 -270.32331)
		(end 84.166202 -270.427704)
		(width 0.088646)
		(layer "In2.Cu")
		(net "M_A_CPU1_SA_DQ<12>")
	)
	(segment
		(start 63.201042 -301.818802)
		(end 62.883542 -301.818802)
		(width 0.18288)
		(layer "In2.Cu")
		(net "M_A_CPU1_SA_DQ<12>")
	)
	(segment
		(start 64.386714 -300.785022)
		(end 64.013588 -300.411896)
		(width 0.18288)
		(layer "In2.Cu")
		(net "M_A_CPU1_SA_DQ<12>")
	)
	(segment
		(start 86.658196 -269.059152)
		(end 86.649306 -269.064232)
		(width 0.088646)
		(layer "In2.Cu")
		(net "M_A_CPU1_SA_DQ<12>")
	)
	(segment
		(start 86.470744 -269.38351)
		(end 86.470744 -269.402052)
		(width 0.088646)
		(layer "In2.Cu")
		(net "M_A_CPU1_SA_DQ<12>")
	)
	(segment
		(start 62.690502 -301.20971)
		(end 62.497462 -301.01667)
		(width 0.18288)
		(layer "In2.Cu")
		(net "M_A_CPU1_SA_DQ<12>")
	)
	(segment
		(start 67.921886 -295.073578)
		(end 67.340734 -295.31437)
		(width 0.18288)
		(layer "In2.Cu")
		(net "M_A_CPU1_SA_DQ<12>")
	)
	(segment
		(start 67.168268 -299.809408)
		(end 66.991484 -300.236128)
		(width 0.18288)
		(layer "In2.Cu")
		(net "M_A_CPU1_SA_DQ<12>")
	)
	(segment
		(start 75.892406 -280.200354)
		(end 74.876152 -282.653486)
		(width 0.18288)
		(layer "In2.Cu")
		(net "M_A_CPU1_SA_DQ<12>")
	)
	(segment
		(start 80.403192 -275.689568)
		(end 75.892406 -280.200354)
		(width 0.18288)
		(layer "In2.Cu")
		(net "M_A_CPU1_SA_DQ<12>")
	)
	(segment
		(start 88.724994 -269.38351)
		(end 88.000332 -269.075408)
		(width 0.088646)
		(layer "In2.Cu")
		(net "M_A_CPU1_SA_DQ<12>")
	)
	(segment
		(start 65.090294 -300.785022)
		(end 65.090294 -301.178976)
		(width 0.18288)
		(layer "In2.Cu")
		(net "M_A_CPU1_SA_DQ<12>")
	)
	(segment
		(start 81.462626 -273.13128)
		(end 80.403192 -275.689568)
		(width 0.18288)
		(layer "In2.Cu")
		(net "M_A_CPU1_SA_DQ<12>")
	)
	(segment
		(start 85.00491 -270.32331)
		(end 84.270596 -270.32331)
		(width 0.088646)
		(layer "In2.Cu")
		(net "M_A_CPU1_SA_DQ<12>")
	)
	(segment
		(start 63.65367 -300.411896)
		(end 63.394082 -300.671484)
		(width 0.18288)
		(layer "In2.Cu")
		(net "M_A_CPU1_SA_DQ<12>")
	)
	(segment
		(start 62.690502 -301.625762)
		(end 62.690502 -301.20971)
		(width 0.18288)
		(layer "In2.Cu")
		(net "M_A_CPU1_SA_DQ<12>")
	)
	(segment
		(start 67.340734 -295.31437)
		(end 67.168268 -295.731184)
		(width 0.18288)
		(layer "In2.Cu")
		(net "M_A_CPU1_SA_DQ<12>")
	)
	(segment
		(start 65.283588 -300.591728)
		(end 65.090294 -300.785022)
		(width 0.18288)
		(layer "In2.Cu")
		(net "M_A_CPU1_SA_DQ<12>")
	)
	(segment
		(start 64.579754 -301.372016)
		(end 64.386714 -301.178976)
		(width 0.18288)
		(layer "In2.Cu")
		(net "M_A_CPU1_SA_DQ<12>")
	)
	(segment
		(start 63.394082 -300.671484)
		(end 63.394082 -301.625762)
		(width 0.18288)
		(layer "In2.Cu")
		(net "M_A_CPU1_SA_DQ<12>")
	)
	(segment
		(start 64.897254 -301.372016)
		(end 64.579754 -301.372016)
		(width 0.18288)
		(layer "In2.Cu")
		(net "M_A_CPU1_SA_DQ<12>")
	)
	(segment
		(start 64.013588 -300.411896)
		(end 63.65367 -300.411896)
		(width 0.18288)
		(layer "In2.Cu")
		(net "M_A_CPU1_SA_DQ<12>")
	)
	(segment
		(start 85.914484 -269.981426)
		(end 85.346794 -269.981426)
		(width 0.088646)
		(layer "In2.Cu")
		(net "M_A_CPU1_SA_DQ<12>")
	)
	(segment
		(start 86.188296 -269.873222)
		(end 86.076536 -269.937992)
		(width 0.088646)
		(layer "In2.Cu")
		(net "M_A_CPU1_SA_DQ<12>")
	)
	(segment
		(start 85.346794 -269.981426)
		(end 85.00491 -270.32331)
		(width 0.088646)
		(layer "In2.Cu")
		(net "M_A_CPU1_SA_DQ<12>")
	)
	(segment
		(start 88.000332 -269.075408)
		(end 87.972392 -269.059152)
		(width 0.088646)
		(layer "In2.Cu")
		(net "M_A_CPU1_SA_DQ<12>")
	)
	(segment
		(start 62.883542 -301.818802)
		(end 62.690502 -301.625762)
		(width 0.18288)
		(layer "In2.Cu")
		(net "M_A_CPU1_SA_DQ<12>")
	)
	(arc
		(start 86.076536 -269.937992)
		(mid 85.998369 -269.970371)
		(end 85.914484 -269.981426)
		(width 0.088646)
		(layer "In2.Cu")
		(net "M_A_CPU1_SA_DQ<12>")
	)
	(arc
		(start 87.972392 -269.059152)
		(mid 87.785194 -269.009009)
		(end 87.597996 -269.059152)
		(width 0.088646)
		(layer "In2.Cu")
		(net "M_A_CPU1_SA_DQ<12>")
	)
	(arc
		(start 87.597996 -269.059152)
		(mid 87.315294 -269.134928)
		(end 87.032592 -269.059152)
		(width 0.088646)
		(layer "In2.Cu")
		(net "M_A_CPU1_SA_DQ<12>")
	)
	(arc
		(start 86.470744 -269.402052)
		(mid 86.390582 -269.674241)
		(end 86.188296 -269.873222)
		(width 0.088646)
		(layer "In2.Cu")
		(net "M_A_CPU1_SA_DQ<12>")
	)
	(arc
		(start 87.032592 -269.059152)
		(mid 86.845394 -269.009009)
		(end 86.658196 -269.059152)
		(width 0.088646)
		(layer "In2.Cu")
		(net "M_A_CPU1_SA_DQ<12>")
	)
	(arc
		(start 86.649306 -269.064232)
		(mid 86.518392 -269.200592)
		(end 86.470744 -269.38351)
		(width 0.088646)
		(layer "In2.Cu")
		(net "M_A_CPU1_SA_DQ<12>")
	)
	(segment
		(start 64.018922 -304.591466)
		(end 63.532766 -304.591466)
		(width 0.20066)
		(layer "F.Cu")
		(net "M_A_CPU1_SA_DQ<11>")
	)
	(segment
		(start 65.047114 -304.416714)
		(end 64.193674 -304.416714)
		(width 0.20066)
		(layer "F.Cu")
		(net "M_A_CPU1_SA_DQ<11>")
	)
	(segment
		(start 90.604848 -270.475456)
		(end 90.604848 -271.011142)
		(width 0.20066)
		(layer "F.Cu")
		(net "M_A_CPU1_SA_DQ<11>")
	)
	(segment
		(start 62.147958 -304.841656)
		(end 62.097412 -304.841656)
		(width 0.101854)
		(layer "F.Cu")
		(net "M_A_CPU1_SA_DQ<11>")
	)
	(segment
		(start 62.829694 -304.540666)
		(end 62.829694 -304.711608)
		(width 0.20066)
		(layer "F.Cu")
		(net "M_A_CPU1_SA_DQ<11>")
	)
	(segment
		(start 59.314842 -304.542444)
		(end 59.188858 -304.41646)
		(width 0.20066)
		(layer "F.Cu")
		(net "M_A_CPU1_SA_DQ<11>")
	)
	(segment
		(start 59.188604 -304.416714)
		(end 57.503314 -304.416714)
		(width 0.20066)
		(layer "F.Cu")
		(net "M_A_CPU1_SA_DQ<11>")
	)
	(segment
		(start 66.152014 -304.416714)
		(end 65.047114 -304.416714)
		(width 0.20066)
		(layer "F.Cu")
		(net "M_A_CPU1_SA_DQ<11>")
	)
	(segment
		(start 62.999366 -304.370994)
		(end 62.829694 -304.540666)
		(width 0.20066)
		(layer "F.Cu")
		(net "M_A_CPU1_SA_DQ<11>")
	)
	(segment
		(start 59.862212 -304.841656)
		(end 59.844432 -304.859436)
		(width 0.101854)
		(layer "F.Cu")
		(net "M_A_CPU1_SA_DQ<11>")
	)
	(segment
		(start 64.193674 -304.416714)
		(end 64.018922 -304.591466)
		(width 0.20066)
		(layer "F.Cu")
		(net "M_A_CPU1_SA_DQ<11>")
	)
	(segment
		(start 59.314842 -304.702464)
		(end 59.314842 -304.542444)
		(width 0.20066)
		(layer "F.Cu")
		(net "M_A_CPU1_SA_DQ<11>")
	)
	(segment
		(start 62.699646 -304.841656)
		(end 62.147958 -304.841656)
		(width 0.20066)
		(layer "F.Cu")
		(net "M_A_CPU1_SA_DQ<11>")
	)
	(segment
		(start 63.532766 -304.591466)
		(end 63.312294 -304.370994)
		(width 0.20066)
		(layer "F.Cu")
		(net "M_A_CPU1_SA_DQ<11>")
	)
	(segment
		(start 59.844432 -304.859436)
		(end 59.822842 -304.859436)
		(width 0.101854)
		(layer "F.Cu")
		(net "M_A_CPU1_SA_DQ<11>")
	)
	(segment
		(start 90.604848 -271.011142)
		(end 90.604594 -271.011396)
		(width 0.20066)
		(layer "F.Cu")
		(net "M_A_CPU1_SA_DQ<11>")
	)
	(segment
		(start 59.188858 -304.41646)
		(end 59.188604 -304.416714)
		(width 0.20066)
		(layer "F.Cu")
		(net "M_A_CPU1_SA_DQ<11>")
	)
	(segment
		(start 59.822842 -304.859436)
		(end 59.471814 -304.859436)
		(width 0.20066)
		(layer "F.Cu")
		(net "M_A_CPU1_SA_DQ<11>")
	)
	(segment
		(start 62.097412 -304.841656)
		(end 59.862212 -304.841656)
		(width 0.1016)
		(layer "F.Cu")
		(net "M_A_CPU1_SA_DQ<11>")
	)
	(segment
		(start 62.829694 -304.711608)
		(end 62.699646 -304.841656)
		(width 0.20066)
		(layer "F.Cu")
		(net "M_A_CPU1_SA_DQ<11>")
	)
	(segment
		(start 59.471814 -304.859436)
		(end 59.314842 -304.702464)
		(width 0.20066)
		(layer "F.Cu")
		(net "M_A_CPU1_SA_DQ<11>")
	)
	(segment
		(start 63.312294 -304.370994)
		(end 62.999366 -304.370994)
		(width 0.20066)
		(layer "F.Cu")
		(net "M_A_CPU1_SA_DQ<11>")
	)
	(segment
		(start 73.704196 -287.943544)
		(end 73.452482 -288.047684)
		(width 0.18288)
		(layer "In2.Cu")
		(net "M_A_CPU1_SA_DQ<11>")
	)
	(segment
		(start 71.714868 -292.243764)
		(end 71.819008 -292.495478)
		(width 0.18288)
		(layer "In2.Cu")
		(net "M_A_CPU1_SA_DQ<11>")
	)
	(segment
		(start 73.062338 -289.963098)
		(end 73.166732 -290.21532)
		(width 0.18288)
		(layer "In2.Cu")
		(net "M_A_CPU1_SA_DQ<11>")
	)
	(segment
		(start 83.056984 -273.909028)
		(end 81.767172 -277.021544)
		(width 0.18288)
		(layer "In2.Cu")
		(net "M_A_CPU1_SA_DQ<11>")
	)
	(segment
		(start 87.59825 -271.335754)
		(end 87.597996 -271.335754)
		(width 0.088646)
		(layer "In2.Cu")
		(net "M_A_CPU1_SA_DQ<11>")
	)
	(segment
		(start 72.357996 -291.194998)
		(end 72.52081 -291.262562)
		(width 0.18288)
		(layer "In2.Cu")
		(net "M_A_CPU1_SA_DQ<11>")
	)
	(segment
		(start 72.251316 -291.913056)
		(end 72.088502 -291.845492)
		(width 0.18288)
		(layer "In2.Cu")
		(net "M_A_CPU1_SA_DQ<11>")
	)
	(segment
		(start 73.86955 -288.012124)
		(end 73.704196 -287.943544)
		(width 0.18288)
		(layer "In2.Cu")
		(net "M_A_CPU1_SA_DQ<11>")
	)
	(segment
		(start 73.044812 -290.508944)
		(end 72.792844 -290.613592)
		(width 0.18288)
		(layer "In2.Cu")
		(net "M_A_CPU1_SA_DQ<11>")
	)
	(segment
		(start 71.557134 -293.149274)
		(end 71.305166 -293.253414)
		(width 0.18288)
		(layer "In2.Cu")
		(net "M_A_CPU1_SA_DQ<11>")
	)
	(segment
		(start 72.625204 -291.514784)
		(end 72.503284 -291.808408)
		(width 0.18288)
		(layer "In2.Cu")
		(net "M_A_CPU1_SA_DQ<11>")
	)
	(segment
		(start 88.537796 -270.687038)
		(end 88.537796 -270.687292)
		(width 0.088646)
		(layer "In2.Cu")
		(net "M_A_CPU1_SA_DQ<11>")
	)
	(segment
		(start 72.375776 -290.649152)
		(end 72.253856 -290.943284)
		(width 0.18288)
		(layer "In2.Cu")
		(net "M_A_CPU1_SA_DQ<11>")
	)
	(segment
		(start 71.836788 -291.949632)
		(end 71.714868 -292.243764)
		(width 0.18288)
		(layer "In2.Cu")
		(net "M_A_CPU1_SA_DQ<11>")
	)
	(segment
		(start 89.47912 -271.35709)
		(end 89.327228 -271.257014)
		(width 0.088646)
		(layer "In2.Cu")
		(net "M_A_CPU1_SA_DQ<11>")
	)
	(segment
		(start 72.088502 -291.845492)
		(end 71.836788 -291.949632)
		(width 0.18288)
		(layer "In2.Cu")
		(net "M_A_CPU1_SA_DQ<11>")
	)
	(segment
		(start 69.466968 -300.496732)
		(end 68.478654 -302.882554)
		(width 0.18288)
		(layer "In2.Cu")
		(net "M_A_CPU1_SA_DQ<11>")
	)
	(segment
		(start 72.253856 -290.943284)
		(end 72.357996 -291.194998)
		(width 0.18288)
		(layer "In2.Cu")
		(net "M_A_CPU1_SA_DQ<11>")
	)
	(segment
		(start 72.62749 -290.545012)
		(end 72.375776 -290.649152)
		(width 0.18288)
		(layer "In2.Cu")
		(net "M_A_CPU1_SA_DQ<11>")
	)
	(segment
		(start 90.604594 -271.011396)
		(end 89.879932 -271.319498)
		(width 0.088646)
		(layer "In2.Cu")
		(net "M_A_CPU1_SA_DQ<11>")
	)
	(segment
		(start 73.434702 -288.59353)
		(end 73.600818 -288.662364)
		(width 0.18288)
		(layer "In2.Cu")
		(net "M_A_CPU1_SA_DQ<11>")
	)
	(segment
		(start 68.478654 -302.882554)
		(end 66.944494 -304.416714)
		(width 0.18288)
		(layer "In2.Cu")
		(net "M_A_CPU1_SA_DQ<11>")
	)
	(segment
		(start 73.166732 -290.21532)
		(end 73.044812 -290.508944)
		(width 0.18288)
		(layer "In2.Cu")
		(net "M_A_CPU1_SA_DQ<11>")
	)
	(segment
		(start 89.879932 -271.319498)
		(end 89.816432 -271.356582)
		(width 0.088646)
		(layer "In2.Cu")
		(net "M_A_CPU1_SA_DQ<11>")
	)
	(segment
		(start 78.065884 -280.722832)
		(end 77.959204 -280.980642)
		(width 0.18288)
		(layer "In2.Cu")
		(net "M_A_CPU1_SA_DQ<11>")
	)
	(segment
		(start 81.767172 -277.021544)
		(end 78.065884 -280.722832)
		(width 0.18288)
		(layer "In2.Cu")
		(net "M_A_CPU1_SA_DQ<11>")
	)
	(segment
		(start 73.705212 -288.914586)
		(end 73.583292 -289.20821)
		(width 0.18288)
		(layer "In2.Cu")
		(net "M_A_CPU1_SA_DQ<11>")
	)
	(segment
		(start 66.944494 -304.416714)
		(end 66.152014 -304.416714)
		(width 0.18288)
		(layer "In2.Cu")
		(net "M_A_CPU1_SA_DQ<11>")
	)
	(segment
		(start 71.981822 -292.563042)
		(end 72.086216 -292.815264)
		(width 0.18288)
		(layer "In2.Cu")
		(net "M_A_CPU1_SA_DQ<11>")
	)
	(segment
		(start 73.331324 -289.312858)
		(end 73.166478 -289.244532)
		(width 0.18288)
		(layer "In2.Cu")
		(net "M_A_CPU1_SA_DQ<11>")
	)
	(segment
		(start 86.841584 -271.482312)
		(end 85.4837 -271.482312)
		(width 0.088646)
		(layer "In2.Cu")
		(net "M_A_CPU1_SA_DQ<11>")
	)
	(segment
		(start 75.12939 -285.475426)
		(end 74.815192 -286.233616)
		(width 0.18288)
		(layer "In2.Cu")
		(net "M_A_CPU1_SA_DQ<11>")
	)
	(segment
		(start 73.975214 -287.293558)
		(end 74.139044 -287.36163)
		(width 0.18288)
		(layer "In2.Cu")
		(net "M_A_CPU1_SA_DQ<11>")
	)
	(segment
		(start 71.819008 -292.495478)
		(end 71.981822 -292.563042)
		(width 0.18288)
		(layer "In2.Cu")
		(net "M_A_CPU1_SA_DQ<11>")
	)
	(segment
		(start 87.606632 -271.34058)
		(end 87.59825 -271.335754)
		(width 0.088646)
		(layer "In2.Cu")
		(net "M_A_CPU1_SA_DQ<11>")
	)
	(segment
		(start 89.327228 -271.257014)
		(end 89.177114 -270.997172)
		(width 0.088646)
		(layer "In2.Cu")
		(net "M_A_CPU1_SA_DQ<11>")
	)
	(segment
		(start 73.583292 -289.20821)
		(end 73.331324 -289.312858)
		(width 0.18288)
		(layer "In2.Cu")
		(net "M_A_CPU1_SA_DQ<11>")
	)
	(segment
		(start 69.466968 -297.694096)
		(end 69.466968 -300.496732)
		(width 0.18288)
		(layer "In2.Cu")
		(net "M_A_CPU1_SA_DQ<11>")
	)
	(segment
		(start 72.503284 -291.808408)
		(end 72.251316 -291.913056)
		(width 0.18288)
		(layer "In2.Cu")
		(net "M_A_CPU1_SA_DQ<11>")
	)
	(segment
		(start 85.352128 -271.613884)
		(end 83.056984 -273.909028)
		(width 0.18288)
		(layer "In2.Cu")
		(net "M_A_CPU1_SA_DQ<11>")
	)
	(segment
		(start 77.959204 -280.980642)
		(end 76.781406 -283.82341)
		(width 0.18288)
		(layer "In2.Cu")
		(net "M_A_CPU1_SA_DQ<11>")
	)
	(segment
		(start 74.243438 -287.613852)
		(end 74.121518 -287.907476)
		(width 0.18288)
		(layer "In2.Cu")
		(net "M_A_CPU1_SA_DQ<11>")
	)
	(segment
		(start 74.208894 -286.446214)
		(end 74.05243 -286.602678)
		(width 0.18288)
		(layer "In2.Cu")
		(net "M_A_CPU1_SA_DQ<11>")
	)
	(segment
		(start 74.602594 -286.446214)
		(end 74.208894 -286.446214)
		(width 0.18288)
		(layer "In2.Cu")
		(net "M_A_CPU1_SA_DQ<11>")
	)
	(segment
		(start 72.086216 -292.815264)
		(end 71.964296 -293.108888)
		(width 0.18288)
		(layer "In2.Cu")
		(net "M_A_CPU1_SA_DQ<11>")
	)
	(segment
		(start 73.452482 -288.047684)
		(end 73.330562 -288.341816)
		(width 0.18288)
		(layer "In2.Cu")
		(net "M_A_CPU1_SA_DQ<11>")
	)
	(segment
		(start 72.52081 -291.262562)
		(end 72.625204 -291.514784)
		(width 0.18288)
		(layer "In2.Cu")
		(net "M_A_CPU1_SA_DQ<11>")
	)
	(segment
		(start 74.815192 -286.233616)
		(end 74.602594 -286.446214)
		(width 0.18288)
		(layer "In2.Cu")
		(net "M_A_CPU1_SA_DQ<11>")
	)
	(segment
		(start 73.330562 -288.341816)
		(end 73.434702 -288.59353)
		(width 0.18288)
		(layer "In2.Cu")
		(net "M_A_CPU1_SA_DQ<11>")
	)
	(segment
		(start 85.4837 -271.482312)
		(end 85.352128 -271.613884)
		(width 0.088646)
		(layer "In2.Cu")
		(net "M_A_CPU1_SA_DQ<11>")
	)
	(segment
		(start 72.792844 -290.613592)
		(end 72.62749 -290.545012)
		(width 0.18288)
		(layer "In2.Cu")
		(net "M_A_CPU1_SA_DQ<11>")
	)
	(segment
		(start 73.870566 -287.04159)
		(end 73.975214 -287.293558)
		(width 0.18288)
		(layer "In2.Cu")
		(net "M_A_CPU1_SA_DQ<11>")
	)
	(segment
		(start 72.792844 -289.642804)
		(end 72.896984 -289.894518)
		(width 0.18288)
		(layer "In2.Cu")
		(net "M_A_CPU1_SA_DQ<11>")
	)
	(segment
		(start 71.964296 -293.108888)
		(end 71.712328 -293.213536)
		(width 0.18288)
		(layer "In2.Cu")
		(net "M_A_CPU1_SA_DQ<11>")
	)
	(segment
		(start 72.914764 -289.348672)
		(end 72.792844 -289.642804)
		(width 0.18288)
		(layer "In2.Cu")
		(net "M_A_CPU1_SA_DQ<11>")
	)
	(segment
		(start 87.972646 -271.3355)
		(end 87.972392 -271.335754)
		(width 0.088646)
		(layer "In2.Cu")
		(net "M_A_CPU1_SA_DQ<11>")
	)
	(segment
		(start 74.121518 -287.907476)
		(end 73.86955 -288.012124)
		(width 0.18288)
		(layer "In2.Cu")
		(net "M_A_CPU1_SA_DQ<11>")
	)
	(segment
		(start 73.166478 -289.244532)
		(end 72.914764 -289.348672)
		(width 0.18288)
		(layer "In2.Cu")
		(net "M_A_CPU1_SA_DQ<11>")
	)
	(segment
		(start 71.712328 -293.213536)
		(end 71.557134 -293.149274)
		(width 0.18288)
		(layer "In2.Cu")
		(net "M_A_CPU1_SA_DQ<11>")
	)
	(segment
		(start 88.350344 -271.011396)
		(end 88.050116 -271.276064)
		(width 0.088646)
		(layer "In2.Cu")
		(net "M_A_CPU1_SA_DQ<11>")
	)
	(segment
		(start 72.896984 -289.894518)
		(end 73.062338 -289.963098)
		(width 0.18288)
		(layer "In2.Cu")
		(net "M_A_CPU1_SA_DQ<11>")
	)
	(segment
		(start 74.05243 -286.602678)
		(end 73.870566 -287.04159)
		(width 0.18288)
		(layer "In2.Cu")
		(net "M_A_CPU1_SA_DQ<11>")
	)
	(segment
		(start 71.305166 -293.253414)
		(end 69.466968 -297.694096)
		(width 0.18288)
		(layer "In2.Cu")
		(net "M_A_CPU1_SA_DQ<11>")
	)
	(segment
		(start 73.600818 -288.662364)
		(end 73.705212 -288.914586)
		(width 0.18288)
		(layer "In2.Cu")
		(net "M_A_CPU1_SA_DQ<11>")
	)
	(segment
		(start 76.781406 -283.82341)
		(end 75.12939 -285.475426)
		(width 0.18288)
		(layer "In2.Cu")
		(net "M_A_CPU1_SA_DQ<11>")
	)
	(segment
		(start 74.139044 -287.36163)
		(end 74.243438 -287.613852)
		(width 0.18288)
		(layer "In2.Cu")
		(net "M_A_CPU1_SA_DQ<11>")
	)
	(arc
		(start 87.032592 -271.335754)
		(mid 86.932297 -271.402786)
		(end 86.841584 -271.482312)
		(width 0.088646)
		(layer "In2.Cu")
		(net "M_A_CPU1_SA_DQ<11>")
	)
	(arc
		(start 88.537796 -270.687292)
		(mid 88.400573 -270.824189)
		(end 88.350344 -271.011396)
		(width 0.088646)
		(layer "In2.Cu")
		(net "M_A_CPU1_SA_DQ<11>")
	)
	(arc
		(start 88.912192 -270.687038)
		(mid 88.724994 -270.636895)
		(end 88.537796 -270.687038)
		(width 0.088646)
		(layer "In2.Cu")
		(net "M_A_CPU1_SA_DQ<11>")
	)
	(arc
		(start 89.177114 -270.997172)
		(mid 89.071293 -270.819352)
		(end 88.912192 -270.687038)
		(width 0.088646)
		(layer "In2.Cu")
		(net "M_A_CPU1_SA_DQ<11>")
	)
	(arc
		(start 88.050116 -271.276064)
		(mid 88.013332 -271.308326)
		(end 87.972646 -271.3355)
		(width 0.088646)
		(layer "In2.Cu")
		(net "M_A_CPU1_SA_DQ<11>")
	)
	(arc
		(start 87.972392 -271.335754)
		(mid 87.790141 -271.385865)
		(end 87.606632 -271.34058)
		(width 0.088646)
		(layer "In2.Cu")
		(net "M_A_CPU1_SA_DQ<11>")
	)
	(arc
		(start 87.597996 -271.335754)
		(mid 87.315294 -271.259978)
		(end 87.032592 -271.335754)
		(width 0.088646)
		(layer "In2.Cu")
		(net "M_A_CPU1_SA_DQ<11>")
	)
	(arc
		(start 89.816432 -271.356582)
		(mid 89.647835 -271.402167)
		(end 89.47912 -271.35709)
		(width 0.088646)
		(layer "In2.Cu")
		(net "M_A_CPU1_SA_DQ<11>")
	)
	(segment
		(start 58.96102 -306.116736)
		(end 57.503314 -306.116736)
		(width 0.20066)
		(layer "F.Cu")
		(net "M_A_CPU1_SA_DQ<10>")
	)
	(segment
		(start 62.913006 -305.8668)
		(end 62.737746 -305.69154)
		(width 0.20066)
		(layer "F.Cu")
		(net "M_A_CPU1_SA_DQ<10>")
	)
	(segment
		(start 63.399416 -306.295044)
		(end 63.102998 -306.295044)
		(width 0.20066)
		(layer "F.Cu")
		(net "M_A_CPU1_SA_DQ<10>")
	)
	(segment
		(start 59.85129 -305.69154)
		(end 59.83097 -305.67122)
		(width 0.101854)
		(layer "F.Cu")
		(net "M_A_CPU1_SA_DQ<10>")
	)
	(segment
		(start 59.822842 -305.67122)
		(end 59.238388 -305.67122)
		(width 0.20066)
		(layer "F.Cu")
		(net "M_A_CPU1_SA_DQ<10>")
	)
	(segment
		(start 59.887612 -305.69154)
		(end 59.85129 -305.69154)
		(width 0.101854)
		(layer "F.Cu")
		(net "M_A_CPU1_SA_DQ<10>")
	)
	(segment
		(start 59.102752 -305.806856)
		(end 59.102752 -305.975004)
		(width 0.20066)
		(layer "F.Cu")
		(net "M_A_CPU1_SA_DQ<10>")
	)
	(segment
		(start 63.102998 -306.295044)
		(end 62.913006 -306.105052)
		(width 0.20066)
		(layer "F.Cu")
		(net "M_A_CPU1_SA_DQ<10>")
	)
	(segment
		(start 59.83097 -305.67122)
		(end 59.822842 -305.67122)
		(width 0.101854)
		(layer "F.Cu")
		(net "M_A_CPU1_SA_DQ<10>")
	)
	(segment
		(start 63.578232 -306.116736)
		(end 63.577978 -306.116482)
		(width 0.20066)
		(layer "F.Cu")
		(net "M_A_CPU1_SA_DQ<10>")
	)
	(segment
		(start 62.136274 -305.69154)
		(end 59.887612 -305.69154)
		(width 0.1016)
		(layer "F.Cu")
		(net "M_A_CPU1_SA_DQ<10>")
	)
	(segment
		(start 66.152014 -306.116736)
		(end 65.047114 -306.116736)
		(width 0.20066)
		(layer "F.Cu")
		(net "M_A_CPU1_SA_DQ<10>")
	)
	(segment
		(start 62.147958 -305.69154)
		(end 62.136274 -305.69154)
		(width 0.101854)
		(layer "F.Cu")
		(net "M_A_CPU1_SA_DQ<10>")
	)
	(segment
		(start 62.913006 -306.105052)
		(end 62.913006 -305.8668)
		(width 0.20066)
		(layer "F.Cu")
		(net "M_A_CPU1_SA_DQ<10>")
	)
	(segment
		(start 90.134694 -271.289272)
		(end 90.134694 -271.825212)
		(width 0.20066)
		(layer "F.Cu")
		(net "M_A_CPU1_SA_DQ<10>")
	)
	(segment
		(start 59.102752 -305.975004)
		(end 58.96102 -306.116736)
		(width 0.20066)
		(layer "F.Cu")
		(net "M_A_CPU1_SA_DQ<10>")
	)
	(segment
		(start 63.577978 -306.116482)
		(end 63.399416 -306.295044)
		(width 0.20066)
		(layer "F.Cu")
		(net "M_A_CPU1_SA_DQ<10>")
	)
	(segment
		(start 62.737746 -305.69154)
		(end 62.147958 -305.69154)
		(width 0.20066)
		(layer "F.Cu")
		(net "M_A_CPU1_SA_DQ<10>")
	)
	(segment
		(start 65.047114 -306.116736)
		(end 63.578232 -306.116736)
		(width 0.20066)
		(layer "F.Cu")
		(net "M_A_CPU1_SA_DQ<10>")
	)
	(segment
		(start 59.238388 -305.67122)
		(end 59.102752 -305.806856)
		(width 0.20066)
		(layer "F.Cu")
		(net "M_A_CPU1_SA_DQ<10>")
	)
	(segment
		(start 79.556356 -281.616912)
		(end 79.780638 -281.709876)
		(width 0.18288)
		(layer "In2.Cu")
		(net "M_A_CPU1_SA_DQ<10>")
	)
	(segment
		(start 79.03464 -282.371292)
		(end 78.912974 -282.664662)
		(width 0.18288)
		(layer "In2.Cu")
		(net "M_A_CPU1_SA_DQ<10>")
	)
	(segment
		(start 87.033354 -272.314924)
		(end 87.032846 -272.314924)
		(width 0.088646)
		(layer "In2.Cu")
		(net "M_A_CPU1_SA_DQ<10>")
	)
	(segment
		(start 78.042008 -284.764988)
		(end 76.394056 -286.41294)
		(width 0.18288)
		(layer "In2.Cu")
		(net "M_A_CPU1_SA_DQ<10>")
	)
	(segment
		(start 89.82202 -271.825212)
		(end 89.756742 -271.89049)
		(width 0.088646)
		(layer "In2.Cu")
		(net "M_A_CPU1_SA_DQ<10>")
	)
	(segment
		(start 87.972646 -272.314924)
		(end 87.964264 -272.310098)
		(width 0.088646)
		(layer "In2.Cu")
		(net "M_A_CPU1_SA_DQ<10>")
	)
	(segment
		(start 79.780638 -281.709876)
		(end 79.885032 -281.962098)
		(width 0.18288)
		(layer "In2.Cu")
		(net "M_A_CPU1_SA_DQ<10>")
	)
	(segment
		(start 70.990968 -300.960028)
		(end 69.88302 -303.634648)
		(width 0.18288)
		(layer "In2.Cu")
		(net "M_A_CPU1_SA_DQ<10>")
	)
	(segment
		(start 79.017368 -282.916884)
		(end 79.24165 -283.009848)
		(width 0.18288)
		(layer "In2.Cu")
		(net "M_A_CPU1_SA_DQ<10>")
	)
	(segment
		(start 90.134694 -271.825212)
		(end 89.82202 -271.825212)
		(width 0.088646)
		(layer "In2.Cu")
		(net "M_A_CPU1_SA_DQ<10>")
	)
	(segment
		(start 72.238616 -295.093898)
		(end 72.11695 -295.387776)
		(width 0.18288)
		(layer "In2.Cu")
		(net "M_A_CPU1_SA_DQ<10>")
	)
	(segment
		(start 72.32523 -296.235628)
		(end 72.073008 -296.340276)
		(width 0.18288)
		(layer "In2.Cu")
		(net "M_A_CPU1_SA_DQ<10>")
	)
	(segment
		(start 71.91375 -296.274236)
		(end 71.662036 -296.378376)
		(width 0.18288)
		(layer "In2.Cu")
		(net "M_A_CPU1_SA_DQ<10>")
	)
	(segment
		(start 83.936586 -274.49653)
		(end 82.58429 -277.76043)
		(width 0.18288)
		(layer "In2.Cu")
		(net "M_A_CPU1_SA_DQ<10>")
	)
	(segment
		(start 71.124064 -297.679364)
		(end 70.990968 -298.00042)
		(width 0.18288)
		(layer "In2.Cu")
		(net "M_A_CPU1_SA_DQ<10>")
	)
	(segment
		(start 78.972156 -283.659834)
		(end 78.747874 -283.56687)
		(width 0.18288)
		(layer "In2.Cu")
		(net "M_A_CPU1_SA_DQ<10>")
	)
	(segment
		(start 78.747874 -283.56687)
		(end 78.495652 -283.671264)
		(width 0.18288)
		(layer "In2.Cu")
		(net "M_A_CPU1_SA_DQ<10>")
	)
	(segment
		(start 71.644256 -296.924222)
		(end 71.803514 -296.990516)
		(width 0.18288)
		(layer "In2.Cu")
		(net "M_A_CPU1_SA_DQ<10>")
	)
	(segment
		(start 71.540116 -296.672508)
		(end 71.644256 -296.924222)
		(width 0.18288)
		(layer "In2.Cu")
		(net "M_A_CPU1_SA_DQ<10>")
	)
	(segment
		(start 79.346044 -283.26207)
		(end 79.224378 -283.55544)
		(width 0.18288)
		(layer "In2.Cu")
		(net "M_A_CPU1_SA_DQ<10>")
	)
	(segment
		(start 82.58429 -277.76043)
		(end 79.783178 -280.561542)
		(width 0.18288)
		(layer "In2.Cu")
		(net "M_A_CPU1_SA_DQ<10>")
	)
	(segment
		(start 86.786974 -272.29054)
		(end 85.776816 -272.681954)
		(width 0.088646)
		(layer "In2.Cu")
		(net "M_A_CPU1_SA_DQ<10>")
	)
	(segment
		(start 71.53402 -297.640756)
		(end 71.375778 -297.575224)
		(width 0.18288)
		(layer "In2.Cu")
		(net "M_A_CPU1_SA_DQ<10>")
	)
	(segment
		(start 69.88302 -303.634648)
		(end 67.07759 -306.440078)
		(width 0.18288)
		(layer "In2.Cu")
		(net "M_A_CPU1_SA_DQ<10>")
	)
	(segment
		(start 87.987378 -272.32356)
		(end 87.972646 -272.314924)
		(width 0.088646)
		(layer "In2.Cu")
		(net "M_A_CPU1_SA_DQ<10>")
	)
	(segment
		(start 89.477596 -272.314924)
		(end 89.467182 -272.32102)
		(width 0.088646)
		(layer "In2.Cu")
		(net "M_A_CPU1_SA_DQ<10>")
	)
	(segment
		(start 79.783178 -280.561542)
		(end 79.451708 -281.364436)
		(width 0.18288)
		(layer "In2.Cu")
		(net "M_A_CPU1_SA_DQ<10>")
	)
	(segment
		(start 71.375778 -297.575224)
		(end 71.124064 -297.679364)
		(width 0.18288)
		(layer "In2.Cu")
		(net "M_A_CPU1_SA_DQ<10>")
	)
	(segment
		(start 79.24165 -283.009848)
		(end 79.346044 -283.26207)
		(width 0.18288)
		(layer "In2.Cu")
		(net "M_A_CPU1_SA_DQ<10>")
	)
	(segment
		(start 72.342502 -295.690036)
		(end 72.44715 -295.942004)
		(width 0.18288)
		(layer "In2.Cu")
		(net "M_A_CPU1_SA_DQ<10>")
	)
	(segment
		(start 79.763366 -282.255468)
		(end 79.511144 -282.359862)
		(width 0.18288)
		(layer "In2.Cu")
		(net "M_A_CPU1_SA_DQ<10>")
	)
	(segment
		(start 67.07759 -306.440078)
		(end 66.475356 -306.440078)
		(width 0.18288)
		(layer "In2.Cu")
		(net "M_A_CPU1_SA_DQ<10>")
	)
	(segment
		(start 76.394056 -286.41294)
		(end 72.863964 -294.935148)
		(width 0.18288)
		(layer "In2.Cu")
		(net "M_A_CPU1_SA_DQ<10>")
	)
	(segment
		(start 79.224378 -283.55544)
		(end 78.972156 -283.659834)
		(width 0.18288)
		(layer "In2.Cu")
		(net "M_A_CPU1_SA_DQ<10>")
	)
	(segment
		(start 71.803514 -296.990516)
		(end 71.908162 -297.242484)
		(width 0.18288)
		(layer "In2.Cu")
		(net "M_A_CPU1_SA_DQ<10>")
	)
	(segment
		(start 78.495652 -283.671264)
		(end 78.042008 -284.764988)
		(width 0.18288)
		(layer "In2.Cu")
		(net "M_A_CPU1_SA_DQ<10>")
	)
	(segment
		(start 71.662036 -296.378376)
		(end 71.540116 -296.672508)
		(width 0.18288)
		(layer "In2.Cu")
		(net "M_A_CPU1_SA_DQ<10>")
	)
	(segment
		(start 71.908162 -297.242484)
		(end 71.786242 -297.536108)
		(width 0.18288)
		(layer "In2.Cu")
		(net "M_A_CPU1_SA_DQ<10>")
	)
	(segment
		(start 79.885032 -281.962098)
		(end 79.763366 -282.255468)
		(width 0.18288)
		(layer "In2.Cu")
		(net "M_A_CPU1_SA_DQ<10>")
	)
	(segment
		(start 85.703156 -272.72996)
		(end 84.080858 -274.352258)
		(width 0.088646)
		(layer "In2.Cu")
		(net "M_A_CPU1_SA_DQ<10>")
	)
	(segment
		(start 72.611996 -295.039796)
		(end 72.490584 -294.989504)
		(width 0.18288)
		(layer "In2.Cu")
		(net "M_A_CPU1_SA_DQ<10>")
	)
	(segment
		(start 79.511144 -282.359862)
		(end 79.286862 -282.266898)
		(width 0.18288)
		(layer "In2.Cu")
		(net "M_A_CPU1_SA_DQ<10>")
	)
	(segment
		(start 84.080858 -274.352258)
		(end 83.936586 -274.49653)
		(width 0.18288)
		(layer "In2.Cu")
		(net "M_A_CPU1_SA_DQ<10>")
	)
	(segment
		(start 72.490584 -294.989504)
		(end 72.238616 -295.093898)
		(width 0.18288)
		(layer "In2.Cu")
		(net "M_A_CPU1_SA_DQ<10>")
	)
	(segment
		(start 87.598504 -272.314924)
		(end 87.58809 -272.32102)
		(width 0.088646)
		(layer "In2.Cu")
		(net "M_A_CPU1_SA_DQ<10>")
	)
	(segment
		(start 71.786242 -297.536108)
		(end 71.53402 -297.640756)
		(width 0.18288)
		(layer "In2.Cu")
		(net "M_A_CPU1_SA_DQ<10>")
	)
	(segment
		(start 66.475356 -306.440078)
		(end 66.152014 -306.116736)
		(width 0.18288)
		(layer "In2.Cu")
		(net "M_A_CPU1_SA_DQ<10>")
	)
	(segment
		(start 72.863964 -294.935148)
		(end 72.611996 -295.039796)
		(width 0.18288)
		(layer "In2.Cu")
		(net "M_A_CPU1_SA_DQ<10>")
	)
	(segment
		(start 79.451708 -281.364436)
		(end 79.556356 -281.616912)
		(width 0.18288)
		(layer "In2.Cu")
		(net "M_A_CPU1_SA_DQ<10>")
	)
	(segment
		(start 87.022686 -272.309336)
		(end 87.017352 -272.319496)
		(width 0.088646)
		(layer "In2.Cu")
		(net "M_A_CPU1_SA_DQ<10>")
	)
	(segment
		(start 70.990968 -298.00042)
		(end 70.990968 -300.960028)
		(width 0.18288)
		(layer "In2.Cu")
		(net "M_A_CPU1_SA_DQ<10>")
	)
	(segment
		(start 72.44715 -295.942004)
		(end 72.32523 -296.235628)
		(width 0.18288)
		(layer "In2.Cu")
		(net "M_A_CPU1_SA_DQ<10>")
	)
	(segment
		(start 78.912974 -282.664662)
		(end 79.017368 -282.916884)
		(width 0.18288)
		(layer "In2.Cu")
		(net "M_A_CPU1_SA_DQ<10>")
	)
	(segment
		(start 79.286862 -282.266898)
		(end 79.03464 -282.371292)
		(width 0.18288)
		(layer "In2.Cu")
		(net "M_A_CPU1_SA_DQ<10>")
	)
	(segment
		(start 72.22109 -295.63949)
		(end 72.342502 -295.690036)
		(width 0.18288)
		(layer "In2.Cu")
		(net "M_A_CPU1_SA_DQ<10>")
	)
	(segment
		(start 72.11695 -295.387776)
		(end 72.22109 -295.63949)
		(width 0.18288)
		(layer "In2.Cu")
		(net "M_A_CPU1_SA_DQ<10>")
	)
	(segment
		(start 72.073008 -296.340276)
		(end 71.91375 -296.274236)
		(width 0.18288)
		(layer "In2.Cu")
		(net "M_A_CPU1_SA_DQ<10>")
	)
	(arc
		(start 89.467182 -272.32102)
		(mid 89.189004 -272.390712)
		(end 88.912446 -272.314924)
		(width 0.088646)
		(layer "In2.Cu")
		(net "M_A_CPU1_SA_DQ<10>")
	)
	(arc
		(start 88.53805 -272.314924)
		(mid 88.263821 -272.390849)
		(end 87.987378 -272.32356)
		(width 0.088646)
		(layer "In2.Cu")
		(net "M_A_CPU1_SA_DQ<10>")
	)
	(arc
		(start 87.017352 -272.319496)
		(mid 86.948393 -272.291211)
		(end 86.875112 -272.277586)
		(width 0.088646)
		(layer "In2.Cu")
		(net "M_A_CPU1_SA_DQ<10>")
	)
	(arc
		(start 86.875112 -272.277586)
		(mid 86.830314 -272.279092)
		(end 86.786974 -272.29054)
		(width 0.088646)
		(layer "In2.Cu")
		(net "M_A_CPU1_SA_DQ<10>")
	)
	(arc
		(start 88.912446 -272.314924)
		(mid 88.725248 -272.264781)
		(end 88.53805 -272.314924)
		(width 0.088646)
		(layer "In2.Cu")
		(net "M_A_CPU1_SA_DQ<10>")
	)
	(arc
		(start 87.032846 -272.314924)
		(mid 87.027787 -272.312092)
		(end 87.022686 -272.309336)
		(width 0.088646)
		(layer "In2.Cu")
		(net "M_A_CPU1_SA_DQ<10>")
	)
	(arc
		(start 87.58809 -272.32102)
		(mid 87.309912 -272.390712)
		(end 87.033354 -272.314924)
		(width 0.088646)
		(layer "In2.Cu")
		(net "M_A_CPU1_SA_DQ<10>")
	)
	(arc
		(start 85.776816 -272.681954)
		(mid 85.737494 -272.702131)
		(end 85.703156 -272.72996)
		(width 0.088646)
		(layer "In2.Cu")
		(net "M_A_CPU1_SA_DQ<10>")
	)
	(arc
		(start 89.756742 -271.89049)
		(mid 89.667543 -272.135844)
		(end 89.477596 -272.314924)
		(width 0.088646)
		(layer "In2.Cu")
		(net "M_A_CPU1_SA_DQ<10>")
	)
	(arc
		(start 87.964264 -272.310098)
		(mid 87.780756 -272.26482)
		(end 87.598504 -272.314924)
		(width 0.088646)
		(layer "In2.Cu")
		(net "M_A_CPU1_SA_DQ<10>")
	)
	(segment
		(start 85.435694 -281.05608)
		(end 85.080348 -281.411426)
		(width 0.1016)
		(layer "F.Cu")
		(net "M_A_CPU1_SA_DQ<0>")
	)
	(segment
		(start 68.41109 -315.569346)
		(end 68.513198 -315.81598)
		(width 0.20066)
		(layer "F.Cu")
		(net "M_A_CPU1_SA_DQ<0>")
	)
	(segment
		(start 85.080348 -281.411426)
		(end 84.843112 -282.593288)
		(width 0.1016)
		(layer "F.Cu")
		(net "M_A_CPU1_SA_DQ<0>")
	)
	(segment
		(start 59.072018 -315.891672)
		(end 58.704226 -315.891672)
		(width 0.20066)
		(layer "F.Cu")
		(net "M_A_CPU1_SA_DQ<0>")
	)
	(segment
		(start 64.054228 -315.891672)
		(end 64.037972 -315.875416)
		(width 0.101854)
		(layer "F.Cu")
		(net "M_A_CPU1_SA_DQ<0>")
	)
	(segment
		(start 64.037972 -315.875416)
		(end 64.002412 -315.875416)
		(width 0.101854)
		(layer "F.Cu")
		(net "M_A_CPU1_SA_DQ<0>")
	)
	(segment
		(start 68.513198 -315.81598)
		(end 68.40474 -316.077854)
		(width 0.20066)
		(layer "F.Cu")
		(net "M_A_CPU1_SA_DQ<0>")
	)
	(segment
		(start 69.304662 -314.982606)
		(end 68.519548 -315.307472)
		(width 0.20066)
		(layer "F.Cu")
		(net "M_A_CPU1_SA_DQ<0>")
	)
	(segment
		(start 66.60769 -315.955172)
		(end 66.530982 -315.878464)
		(width 0.20066)
		(layer "F.Cu")
		(net "M_A_CPU1_SA_DQ<0>")
	)
	(segment
		(start 67.8561 -316.088268)
		(end 67.753992 -315.841634)
		(width 0.20066)
		(layer "F.Cu")
		(net "M_A_CPU1_SA_DQ<0>")
	)
	(segment
		(start 84.843112 -282.593288)
		(end 84.843112 -298.73194)
		(width 0.1016)
		(layer "F.Cu")
		(net "M_A_CPU1_SA_DQ<0>")
	)
	(segment
		(start 67.492118 -315.733176)
		(end 66.956686 -315.955172)
		(width 0.20066)
		(layer "F.Cu")
		(net "M_A_CPU1_SA_DQ<0>")
	)
	(segment
		(start 84.55152 -299.023532)
		(end 84.55152 -299.283628)
		(width 0.1016)
		(layer "F.Cu")
		(net "M_A_CPU1_SA_DQ<0>")
	)
	(segment
		(start 54.897528 -316.071758)
		(end 54.897528 -316.33414)
		(width 0.20066)
		(layer "F.Cu")
		(net "M_A_CPU1_SA_DQ<0>")
	)
	(segment
		(start 56.40959 -315.891672)
		(end 56.389016 -315.871098)
		(width 0.101854)
		(layer "F.Cu")
		(net "M_A_CPU1_SA_DQ<0>")
	)
	(segment
		(start 66.956686 -315.955172)
		(end 66.60769 -315.955172)
		(width 0.20066)
		(layer "F.Cu")
		(net "M_A_CPU1_SA_DQ<0>")
	)
	(segment
		(start 63.840614 -315.875416)
		(end 62.935104 -316.182502)
		(width 0.20066)
		(layer "F.Cu")
		(net "M_A_CPU1_SA_DQ<0>")
	)
	(segment
		(start 58.704226 -315.891672)
		(end 58.617612 -315.891672)
		(width 0.101854)
		(layer "F.Cu")
		(net "M_A_CPU1_SA_DQ<0>")
	)
	(segment
		(start 84.556854 -300.15815)
		(end 70.593204 -314.1218)
		(width 0.20066)
		(layer "F.Cu")
		(net "M_A_CPU1_SA_DQ<0>")
	)
	(segment
		(start 70.593204 -314.1218)
		(end 69.304662 -314.982606)
		(width 0.20066)
		(layer "F.Cu")
		(net "M_A_CPU1_SA_DQ<0>")
	)
	(segment
		(start 68.519548 -315.307472)
		(end 68.41109 -315.569346)
		(width 0.20066)
		(layer "F.Cu")
		(net "M_A_CPU1_SA_DQ<0>")
	)
	(segment
		(start 60.947046 -316.316614)
		(end 59.49696 -316.316614)
		(width 0.20066)
		(layer "F.Cu")
		(net "M_A_CPU1_SA_DQ<0>")
	)
	(segment
		(start 62.320932 -316.316614)
		(end 60.947046 -316.316614)
		(width 0.20066)
		(layer "F.Cu")
		(net "M_A_CPU1_SA_DQ<0>")
	)
	(segment
		(start 54.027578 -316.316614)
		(end 53.403246 -316.316614)
		(width 0.20066)
		(layer "F.Cu")
		(net "M_A_CPU1_SA_DQ<0>")
	)
	(segment
		(start 58.617612 -315.891672)
		(end 56.458612 -315.891672)
		(width 0.1016)
		(layer "F.Cu")
		(net "M_A_CPU1_SA_DQ<0>")
	)
	(segment
		(start 54.66334 -316.568328)
		(end 54.279292 -316.568328)
		(width 0.20066)
		(layer "F.Cu")
		(net "M_A_CPU1_SA_DQ<0>")
	)
	(segment
		(start 66.130932 -315.891672)
		(end 64.054228 -315.891672)
		(width 0.1016)
		(layer "F.Cu")
		(net "M_A_CPU1_SA_DQ<0>")
	)
	(segment
		(start 66.530982 -315.878464)
		(end 66.186812 -315.878464)
		(width 0.20066)
		(layer "F.Cu")
		(net "M_A_CPU1_SA_DQ<0>")
	)
	(segment
		(start 68.117974 -316.196726)
		(end 67.8561 -316.088268)
		(width 0.20066)
		(layer "F.Cu")
		(net "M_A_CPU1_SA_DQ<0>")
	)
	(segment
		(start 56.37911 -315.871098)
		(end 55.098188 -315.871098)
		(width 0.20066)
		(layer "F.Cu")
		(net "M_A_CPU1_SA_DQ<0>")
	)
	(segment
		(start 84.850478 -299.864526)
		(end 84.556854 -300.15815)
		(width 0.1016)
		(layer "F.Cu")
		(net "M_A_CPU1_SA_DQ<0>")
	)
	(segment
		(start 56.458612 -315.891672)
		(end 56.40959 -315.891672)
		(width 0.101854)
		(layer "F.Cu")
		(net "M_A_CPU1_SA_DQ<0>")
	)
	(segment
		(start 59.49696 -316.316614)
		(end 59.072018 -315.891672)
		(width 0.20066)
		(layer "F.Cu")
		(net "M_A_CPU1_SA_DQ<0>")
	)
	(segment
		(start 66.186812 -315.878464)
		(end 66.14414 -315.878464)
		(width 0.101854)
		(layer "F.Cu")
		(net "M_A_CPU1_SA_DQ<0>")
	)
	(segment
		(start 84.55152 -299.283628)
		(end 84.850478 -299.582586)
		(width 0.1016)
		(layer "F.Cu")
		(net "M_A_CPU1_SA_DQ<0>")
	)
	(segment
		(start 84.843112 -298.73194)
		(end 84.55152 -299.023532)
		(width 0.1016)
		(layer "F.Cu")
		(net "M_A_CPU1_SA_DQ<0>")
	)
	(segment
		(start 54.897528 -316.33414)
		(end 54.66334 -316.568328)
		(width 0.20066)
		(layer "F.Cu")
		(net "M_A_CPU1_SA_DQ<0>")
	)
	(segment
		(start 54.279292 -316.568328)
		(end 54.027578 -316.316614)
		(width 0.20066)
		(layer "F.Cu")
		(net "M_A_CPU1_SA_DQ<0>")
	)
	(segment
		(start 64.002412 -315.875416)
		(end 63.840614 -315.875416)
		(width 0.20066)
		(layer "F.Cu")
		(net "M_A_CPU1_SA_DQ<0>")
	)
	(segment
		(start 56.389016 -315.871098)
		(end 56.37911 -315.871098)
		(width 0.101854)
		(layer "F.Cu")
		(net "M_A_CPU1_SA_DQ<0>")
	)
	(segment
		(start 67.753992 -315.841634)
		(end 67.492118 -315.733176)
		(width 0.20066)
		(layer "F.Cu")
		(net "M_A_CPU1_SA_DQ<0>")
	)
	(segment
		(start 66.14414 -315.878464)
		(end 66.130932 -315.891672)
		(width 0.101854)
		(layer "F.Cu")
		(net "M_A_CPU1_SA_DQ<0>")
	)
	(segment
		(start 84.850478 -299.582586)
		(end 84.850478 -299.864526)
		(width 0.1016)
		(layer "F.Cu")
		(net "M_A_CPU1_SA_DQ<0>")
	)
	(segment
		(start 55.098188 -315.871098)
		(end 54.897528 -316.071758)
		(width 0.20066)
		(layer "F.Cu")
		(net "M_A_CPU1_SA_DQ<0>")
	)
	(segment
		(start 62.935104 -316.182502)
		(end 62.320932 -316.316614)
		(width 0.20066)
		(layer "F.Cu")
		(net "M_A_CPU1_SA_DQ<0>")
	)
	(segment
		(start 68.40474 -316.077854)
		(end 68.117974 -316.196726)
		(width 0.20066)
		(layer "F.Cu")
		(net "M_A_CPU1_SA_DQ<0>")
	)
	(segment
		(start 77.082396 -261.318756)
		(end 77.081888 -261.319518)
		(width 0.20066)
		(layer "F.Cu")
		(net "M_A_CPU1_SA_CS_N<3>")
	)
	(segment
		(start 66.951098 -266.889992)
		(end 66.824352 -267.016738)
		(width 0.20066)
		(layer "F.Cu")
		(net "M_A_CPU1_SA_CS_N<3>")
	)
	(segment
		(start 77.266038 -261.242556)
		(end 77.082396 -261.318756)
		(width 0.20066)
		(layer "F.Cu")
		(net "M_A_CPU1_SA_CS_N<3>")
	)
	(segment
		(start 86.926928 -258.655566)
		(end 86.29904 -258.655566)
		(width 0.088646)
		(layer "F.Cu")
		(net "M_A_CPU1_SA_CS_N<3>")
	)
	(segment
		(start 77.081888 -261.319518)
		(end 72.171052 -263.35355)
		(width 0.20066)
		(layer "F.Cu")
		(net "M_A_CPU1_SA_CS_N<3>")
	)
	(segment
		(start 87.315294 -258.2672)
		(end 86.926928 -258.655566)
		(width 0.088646)
		(layer "F.Cu")
		(net "M_A_CPU1_SA_CS_N<3>")
	)
	(segment
		(start 79.207614 -259.30098)
		(end 77.266038 -261.242556)
		(width 0.20066)
		(layer "F.Cu")
		(net "M_A_CPU1_SA_CS_N<3>")
	)
	(segment
		(start 83.717638 -258.349242)
		(end 83.007454 -259.059426)
		(width 0.1016)
		(layer "F.Cu")
		(net "M_A_CPU1_SA_CS_N<3>")
	)
	(segment
		(start 69.05117 -266.47394)
		(end 68.046854 -266.889992)
		(width 0.20066)
		(layer "F.Cu")
		(net "M_A_CPU1_SA_CS_N<3>")
	)
	(segment
		(start 68.046854 -266.889992)
		(end 66.951098 -266.889992)
		(width 0.20066)
		(layer "F.Cu")
		(net "M_A_CPU1_SA_CS_N<3>")
	)
	(segment
		(start 86.29904 -258.655566)
		(end 86.188296 -258.591558)
		(width 0.088646)
		(layer "F.Cu")
		(net "M_A_CPU1_SA_CS_N<3>")
	)
	(segment
		(start 83.007454 -259.059426)
		(end 79.522066 -259.059426)
		(width 0.1016)
		(layer "F.Cu")
		(net "M_A_CPU1_SA_CS_N<3>")
	)
	(segment
		(start 84.845906 -258.207256)
		(end 83.859624 -258.207256)
		(width 0.088646)
		(layer "F.Cu")
		(net "M_A_CPU1_SA_CS_N<3>")
	)
	(segment
		(start 79.522066 -259.059426)
		(end 79.397606 -259.110988)
		(width 0.1016)
		(layer "F.Cu")
		(net "M_A_CPU1_SA_CS_N<3>")
	)
	(segment
		(start 85.170772 -258.532122)
		(end 84.845906 -258.207256)
		(width 0.088646)
		(layer "F.Cu")
		(net "M_A_CPU1_SA_CS_N<3>")
	)
	(segment
		(start 79.397606 -259.110988)
		(end 79.207614 -259.30098)
		(width 0.101854)
		(layer "F.Cu")
		(net "M_A_CPU1_SA_CS_N<3>")
	)
	(segment
		(start 66.824352 -267.016738)
		(end 65.047114 -267.016738)
		(width 0.20066)
		(layer "F.Cu")
		(net "M_A_CPU1_SA_CS_N<3>")
	)
	(segment
		(start 72.171052 -263.35355)
		(end 69.05117 -266.47394)
		(width 0.20066)
		(layer "F.Cu")
		(net "M_A_CPU1_SA_CS_N<3>")
	)
	(segment
		(start 83.859624 -258.207256)
		(end 83.717638 -258.349242)
		(width 0.088646)
		(layer "F.Cu")
		(net "M_A_CPU1_SA_CS_N<3>")
	)
	(arc
		(start 86.188296 -258.591558)
		(mid 85.905594 -258.515782)
		(end 85.622892 -258.591558)
		(width 0.088646)
		(layer "F.Cu")
		(net "M_A_CPU1_SA_CS_N<3>")
	)
	(arc
		(start 85.622892 -258.591558)
		(mid 85.435694 -258.641701)
		(end 85.248496 -258.591558)
		(width 0.088646)
		(layer "F.Cu")
		(net "M_A_CPU1_SA_CS_N<3>")
	)
	(arc
		(start 85.248496 -258.591558)
		(mid 85.207687 -258.564386)
		(end 85.170772 -258.532122)
		(width 0.088646)
		(layer "F.Cu")
		(net "M_A_CPU1_SA_CS_N<3>")
	)
	(segment
		(start 72.533764 -263.89584)
		(end 69.149722 -267.280136)
		(width 0.20066)
		(layer "F.Cu")
		(net "M_A_CPU1_SA_CS_N<2>")
	)
	(segment
		(start 64.025272 -267.434568)
		(end 63.977012 -267.434568)
		(width 0.101854)
		(layer "F.Cu")
		(net "M_A_CPU1_SA_CS_N<2>")
	)
	(segment
		(start 86.682072 -258.91744)
		(end 86.36762 -258.91744)
		(width 0.088646)
		(layer "F.Cu")
		(net "M_A_CPU1_SA_CS_N<2>")
	)
	(segment
		(start 83.133946 -259.364226)
		(end 80.096868 -259.364226)
		(width 0.1016)
		(layer "F.Cu")
		(net "M_A_CPU1_SA_CS_N<2>")
	)
	(segment
		(start 62.501272 -267.434568)
		(end 62.069218 -267.866622)
		(width 0.20066)
		(layer "F.Cu")
		(net "M_A_CPU1_SA_CS_N<2>")
	)
	(segment
		(start 66.105532 -267.44168)
		(end 64.032384 -267.44168)
		(width 0.1016)
		(layer "F.Cu")
		(net "M_A_CPU1_SA_CS_N<2>")
	)
	(segment
		(start 66.587878 -267.62837)
		(end 66.395854 -267.436346)
		(width 0.20066)
		(layer "F.Cu")
		(net "M_A_CPU1_SA_CS_N<2>")
	)
	(segment
		(start 84.757514 -258.404106)
		(end 84.094066 -258.404106)
		(width 0.088646)
		(layer "F.Cu")
		(net "M_A_CPU1_SA_CS_N<2>")
	)
	(segment
		(start 85.049106 -258.695698)
		(end 84.757514 -258.404106)
		(width 0.088646)
		(layer "F.Cu")
		(net "M_A_CPU1_SA_CS_N<2>")
	)
	(segment
		(start 66.161412 -267.436346)
		(end 66.110866 -267.436346)
		(width 0.101854)
		(layer "F.Cu")
		(net "M_A_CPU1_SA_CS_N<2>")
	)
	(segment
		(start 77.506068 -261.836408)
		(end 72.533764 -263.89584)
		(width 0.20066)
		(layer "F.Cu")
		(net "M_A_CPU1_SA_CS_N<2>")
	)
	(segment
		(start 66.395854 -267.436346)
		(end 66.161412 -267.436346)
		(width 0.20066)
		(layer "F.Cu")
		(net "M_A_CPU1_SA_CS_N<2>")
	)
	(segment
		(start 84.094066 -258.404106)
		(end 83.768184 -258.729988)
		(width 0.088646)
		(layer "F.Cu")
		(net "M_A_CPU1_SA_CS_N<2>")
	)
	(segment
		(start 66.110866 -267.436346)
		(end 66.105532 -267.44168)
		(width 0.101854)
		(layer "F.Cu")
		(net "M_A_CPU1_SA_CS_N<2>")
	)
	(segment
		(start 86.845648 -259.081016)
		(end 86.682072 -258.91744)
		(width 0.088646)
		(layer "F.Cu")
		(net "M_A_CPU1_SA_CS_N<2>")
	)
	(segment
		(start 64.032384 -267.44168)
		(end 64.025272 -267.434568)
		(width 0.101854)
		(layer "F.Cu")
		(net "M_A_CPU1_SA_CS_N<2>")
	)
	(segment
		(start 77.50683 -261.835138)
		(end 77.506068 -261.836408)
		(width 0.20066)
		(layer "F.Cu")
		(net "M_A_CPU1_SA_CS_N<2>")
	)
	(segment
		(start 63.977012 -267.434568)
		(end 62.501272 -267.434568)
		(width 0.20066)
		(layer "F.Cu")
		(net "M_A_CPU1_SA_CS_N<2>")
	)
	(segment
		(start 68.309998 -267.62837)
		(end 66.587878 -267.62837)
		(width 0.20066)
		(layer "F.Cu")
		(net "M_A_CPU1_SA_CS_N<2>")
	)
	(segment
		(start 80.096868 -259.364226)
		(end 80.01635 -259.3975)
		(width 0.1016)
		(layer "F.Cu")
		(net "M_A_CPU1_SA_CS_N<2>")
	)
	(segment
		(start 62.069218 -267.866622)
		(end 60.947046 -267.866622)
		(width 0.20066)
		(layer "F.Cu")
		(net "M_A_CPU1_SA_CS_N<2>")
	)
	(segment
		(start 69.149722 -267.280136)
		(end 68.309998 -267.62837)
		(width 0.20066)
		(layer "F.Cu")
		(net "M_A_CPU1_SA_CS_N<2>")
	)
	(segment
		(start 77.629766 -261.784084)
		(end 77.50683 -261.835138)
		(width 0.20066)
		(layer "F.Cu")
		(net "M_A_CPU1_SA_CS_N<2>")
	)
	(segment
		(start 80.01635 -259.3975)
		(end 79.812642 -259.601208)
		(width 0.101854)
		(layer "F.Cu")
		(net "M_A_CPU1_SA_CS_N<2>")
	)
	(segment
		(start 83.768184 -258.729988)
		(end 83.133946 -259.364226)
		(width 0.1016)
		(layer "F.Cu")
		(net "M_A_CPU1_SA_CS_N<2>")
	)
	(segment
		(start 86.36762 -258.91744)
		(end 86.092792 -258.756658)
		(width 0.088646)
		(layer "F.Cu")
		(net "M_A_CPU1_SA_CS_N<2>")
	)
	(segment
		(start 79.812642 -259.601208)
		(end 77.629766 -261.784084)
		(width 0.20066)
		(layer "F.Cu")
		(net "M_A_CPU1_SA_CS_N<2>")
	)
	(segment
		(start 85.16366 -258.762754)
		(end 85.049106 -258.695698)
		(width 0.088646)
		(layer "F.Cu")
		(net "M_A_CPU1_SA_CS_N<2>")
	)
	(arc
		(start 85.718396 -258.756658)
		(mid 85.441837 -258.832401)
		(end 85.16366 -258.762754)
		(width 0.088646)
		(layer "F.Cu")
		(net "M_A_CPU1_SA_CS_N<2>")
	)
	(arc
		(start 86.092792 -258.756658)
		(mid 85.905594 -258.706515)
		(end 85.718396 -258.756658)
		(width 0.088646)
		(layer "F.Cu")
		(net "M_A_CPU1_SA_CS_N<2>")
	)
	(segment
		(start 85.15604 -257.987546)
		(end 83.648042 -257.987546)
		(width 0.088646)
		(layer "F.Cu")
		(net "M_A_CPU1_SA_CS_N<1>")
	)
	(segment
		(start 58.39206 -267.016738)
		(end 57.503314 -267.016738)
		(width 0.20066)
		(layer "F.Cu")
		(net "M_A_CPU1_SA_CS_N<1>")
	)
	(segment
		(start 82.880962 -258.754626)
		(end 78.849474 -258.754626)
		(width 0.1016)
		(layer "F.Cu")
		(net "M_A_CPU1_SA_CS_N<1>")
	)
	(segment
		(start 85.435694 -258.2672)
		(end 85.15604 -257.987546)
		(width 0.088646)
		(layer "F.Cu")
		(net "M_A_CPU1_SA_CS_N<1>")
	)
	(segment
		(start 66.33083 -266.608052)
		(end 66.186812 -266.608052)
		(width 0.20066)
		(layer "F.Cu")
		(net "M_A_CPU1_SA_CS_N<1>")
	)
	(segment
		(start 59.59221 -266.549124)
		(end 59.291982 -266.248896)
		(width 0.20066)
		(layer "F.Cu")
		(net "M_A_CPU1_SA_CS_N<1>")
	)
	(segment
		(start 66.71691 -266.221972)
		(end 66.33083 -266.608052)
		(width 0.20066)
		(layer "F.Cu")
		(net "M_A_CPU1_SA_CS_N<1>")
	)
	(segment
		(start 58.998612 -266.361926)
		(end 58.998612 -266.7127)
		(width 0.20066)
		(layer "F.Cu")
		(net "M_A_CPU1_SA_CS_N<1>")
	)
	(segment
		(start 63.798196 -266.591542)
		(end 62.147958 -266.591542)
		(width 0.20066)
		(layer "F.Cu")
		(net "M_A_CPU1_SA_CS_N<1>")
	)
	(segment
		(start 83.648042 -257.987546)
		(end 83.609434 -258.026154)
		(width 0.088646)
		(layer "F.Cu")
		(net "M_A_CPU1_SA_CS_N<1>")
	)
	(segment
		(start 62.147958 -266.591542)
		(end 59.913266 -266.591542)
		(width 0.1016)
		(layer "F.Cu")
		(net "M_A_CPU1_SA_CS_N<1>")
	)
	(segment
		(start 58.920126 -266.791186)
		(end 58.617612 -266.791186)
		(width 0.20066)
		(layer "F.Cu")
		(net "M_A_CPU1_SA_CS_N<1>")
	)
	(segment
		(start 67.98818 -266.221972)
		(end 66.71691 -266.221972)
		(width 0.20066)
		(layer "F.Cu")
		(net "M_A_CPU1_SA_CS_N<1>")
	)
	(segment
		(start 64.002412 -266.612878)
		(end 63.819532 -266.612878)
		(width 0.20066)
		(layer "F.Cu")
		(net "M_A_CPU1_SA_CS_N<1>")
	)
	(segment
		(start 58.617612 -266.791186)
		(end 58.39206 -267.016738)
		(width 0.20066)
		(layer "F.Cu")
		(net "M_A_CPU1_SA_CS_N<1>")
	)
	(segment
		(start 59.822842 -266.549124)
		(end 59.59221 -266.549124)
		(width 0.20066)
		(layer "F.Cu")
		(net "M_A_CPU1_SA_CS_N<1>")
	)
	(segment
		(start 66.179446 -266.608052)
		(end 66.162936 -266.591542)
		(width 0.101854)
		(layer "F.Cu")
		(net "M_A_CPU1_SA_CS_N<1>")
	)
	(segment
		(start 76.657454 -260.802882)
		(end 71.700644 -262.855964)
		(width 0.20066)
		(layer "F.Cu")
		(net "M_A_CPU1_SA_CS_N<1>")
	)
	(segment
		(start 76.903834 -260.700266)
		(end 76.657962 -260.80212)
		(width 0.20066)
		(layer "F.Cu")
		(net "M_A_CPU1_SA_CS_N<1>")
	)
	(segment
		(start 59.870848 -266.549124)
		(end 59.822842 -266.549124)
		(width 0.101854)
		(layer "F.Cu")
		(net "M_A_CPU1_SA_CS_N<1>")
	)
	(segment
		(start 59.913266 -266.591542)
		(end 59.870848 -266.549124)
		(width 0.101854)
		(layer "F.Cu")
		(net "M_A_CPU1_SA_CS_N<1>")
	)
	(segment
		(start 78.849474 -258.754626)
		(end 78.603094 -259.001006)
		(width 0.1016)
		(layer "F.Cu")
		(net "M_A_CPU1_SA_CS_N<1>")
	)
	(segment
		(start 76.657962 -260.80212)
		(end 76.657454 -260.802882)
		(width 0.20066)
		(layer "F.Cu")
		(net "M_A_CPU1_SA_CS_N<1>")
	)
	(segment
		(start 66.186812 -266.608052)
		(end 66.179446 -266.608052)
		(width 0.101854)
		(layer "F.Cu")
		(net "M_A_CPU1_SA_CS_N<1>")
	)
	(segment
		(start 59.111642 -266.248896)
		(end 58.998612 -266.361926)
		(width 0.20066)
		(layer "F.Cu")
		(net "M_A_CPU1_SA_CS_N<1>")
	)
	(segment
		(start 83.609434 -258.026154)
		(end 82.880962 -258.754626)
		(width 0.1016)
		(layer "F.Cu")
		(net "M_A_CPU1_SA_CS_N<1>")
	)
	(segment
		(start 66.162936 -266.591542)
		(end 64.050164 -266.591542)
		(width 0.1016)
		(layer "F.Cu")
		(net "M_A_CPU1_SA_CS_N<1>")
	)
	(segment
		(start 64.050164 -266.591542)
		(end 64.028828 -266.612878)
		(width 0.101854)
		(layer "F.Cu")
		(net "M_A_CPU1_SA_CS_N<1>")
	)
	(segment
		(start 71.700644 -262.855964)
		(end 68.579746 -265.976862)
		(width 0.20066)
		(layer "F.Cu")
		(net "M_A_CPU1_SA_CS_N<1>")
	)
	(segment
		(start 63.819532 -266.612878)
		(end 63.798196 -266.591542)
		(width 0.20066)
		(layer "F.Cu")
		(net "M_A_CPU1_SA_CS_N<1>")
	)
	(segment
		(start 68.579746 -265.976862)
		(end 67.98818 -266.221972)
		(width 0.20066)
		(layer "F.Cu")
		(net "M_A_CPU1_SA_CS_N<1>")
	)
	(segment
		(start 78.603094 -259.001006)
		(end 76.903834 -260.700266)
		(width 0.20066)
		(layer "F.Cu")
		(net "M_A_CPU1_SA_CS_N<1>")
	)
	(segment
		(start 58.998612 -266.7127)
		(end 58.920126 -266.791186)
		(width 0.20066)
		(layer "F.Cu")
		(net "M_A_CPU1_SA_CS_N<1>")
	)
	(segment
		(start 64.028828 -266.612878)
		(end 64.002412 -266.612878)
		(width 0.101854)
		(layer "F.Cu")
		(net "M_A_CPU1_SA_CS_N<1>")
	)
	(segment
		(start 59.291982 -266.248896)
		(end 59.111642 -266.248896)
		(width 0.20066)
		(layer "F.Cu")
		(net "M_A_CPU1_SA_CS_N<1>")
	)
	(segment
		(start 80.651096 -259.669026)
		(end 83.809078 -259.669026)
		(width 0.1016)
		(layer "F.Cu")
		(net "M_A_CPU1_SA_CS_N<0>")
	)
	(segment
		(start 63.95974 -268.291564)
		(end 66.35496 -268.291564)
		(width 0.1016)
		(layer "F.Cu")
		(net "M_A_CPU1_SA_CS_N<0>")
	)
	(segment
		(start 78.307438 -262.01116)
		(end 78.309978 -262.010144)
		(width 0.20066)
		(layer "F.Cu")
		(net "M_A_CPU1_SA_CS_N<0>")
	)
	(segment
		(start 63.498222 -268.299692)
		(end 63.951612 -268.299692)
		(width 0.20066)
		(layer "F.Cu")
		(net "M_A_CPU1_SA_CS_N<0>")
	)
	(segment
		(start 56.482488 -267.44168)
		(end 58.594244 -267.44168)
		(width 0.1016)
		(layer "F.Cu")
		(net "M_A_CPU1_SA_CS_N<0>")
	)
	(segment
		(start 62.062106 -268.27099)
		(end 62.097412 -268.27099)
		(width 0.101854)
		(layer "F.Cu")
		(net "M_A_CPU1_SA_CS_N<0>")
	)
	(segment
		(start 80.405478 -259.914644)
		(end 80.651096 -259.669026)
		(width 0.1016)
		(layer "F.Cu")
		(net "M_A_CPU1_SA_CS_N<0>")
	)
	(segment
		(start 84.041234 -259.669026)
		(end 84.21878 -259.49148)
		(width 0.088646)
		(layer "F.Cu")
		(net "M_A_CPU1_SA_CS_N<0>")
	)
	(segment
		(start 56.407812 -267.40993)
		(end 56.450738 -267.40993)
		(width 0.101854)
		(layer "F.Cu")
		(net "M_A_CPU1_SA_CS_N<0>")
	)
	(segment
		(start 56.450738 -267.40993)
		(end 56.482488 -267.44168)
		(width 0.101854)
		(layer "F.Cu")
		(net "M_A_CPU1_SA_CS_N<0>")
	)
	(segment
		(start 63.951612 -268.299692)
		(end 63.95974 -268.291564)
		(width 0.101854)
		(layer "F.Cu")
		(net "M_A_CPU1_SA_CS_N<0>")
	)
	(segment
		(start 59.727592 -268.284198)
		(end 59.822842 -268.284198)
		(width 0.20066)
		(layer "F.Cu")
		(net "M_A_CPU1_SA_CS_N<0>")
	)
	(segment
		(start 62.372494 -268.27099)
		(end 62.465712 -268.177772)
		(width 0.20066)
		(layer "F.Cu")
		(net "M_A_CPU1_SA_CS_N<0>")
	)
	(segment
		(start 54.480206 -267.866622)
		(end 55.28437 -267.062458)
		(width 0.20066)
		(layer "F.Cu")
		(net "M_A_CPU1_SA_CS_N<0>")
	)
	(segment
		(start 83.809078 -259.669026)
		(end 84.041234 -259.669026)
		(width 0.088646)
		(layer "F.Cu")
		(net "M_A_CPU1_SA_CS_N<0>")
	)
	(segment
		(start 55.932324 -267.40993)
		(end 56.407812 -267.40993)
		(width 0.20066)
		(layer "F.Cu")
		(net "M_A_CPU1_SA_CS_N<0>")
	)
	(segment
		(start 59.822842 -268.284198)
		(end 59.85637 -268.284198)
		(width 0.101854)
		(layer "F.Cu")
		(net "M_A_CPU1_SA_CS_N<0>")
	)
	(segment
		(start 58.615072 -267.420852)
		(end 58.668412 -267.420852)
		(width 0.101854)
		(layer "F.Cu")
		(net "M_A_CPU1_SA_CS_N<0>")
	)
	(segment
		(start 55.584852 -267.062458)
		(end 55.932324 -267.40993)
		(width 0.20066)
		(layer "F.Cu")
		(net "M_A_CPU1_SA_CS_N<0>")
	)
	(segment
		(start 59.85637 -268.284198)
		(end 59.863736 -268.291564)
		(width 0.101854)
		(layer "F.Cu")
		(net "M_A_CPU1_SA_CS_N<0>")
	)
	(segment
		(start 63.376302 -268.177772)
		(end 63.498222 -268.299692)
		(width 0.20066)
		(layer "F.Cu")
		(net "M_A_CPU1_SA_CS_N<0>")
	)
	(segment
		(start 62.041532 -268.291564)
		(end 62.062106 -268.27099)
		(width 0.101854)
		(layer "F.Cu")
		(net "M_A_CPU1_SA_CS_N<0>")
	)
	(segment
		(start 69.51218 -267.822426)
		(end 72.861424 -264.473182)
		(width 0.20066)
		(layer "F.Cu")
		(net "M_A_CPU1_SA_CS_N<0>")
	)
	(segment
		(start 62.465712 -268.177772)
		(end 63.376302 -268.177772)
		(width 0.20066)
		(layer "F.Cu")
		(net "M_A_CPU1_SA_CS_N<0>")
	)
	(segment
		(start 55.28437 -267.062458)
		(end 55.584852 -267.062458)
		(width 0.20066)
		(layer "F.Cu")
		(net "M_A_CPU1_SA_CS_N<0>")
	)
	(segment
		(start 58.594244 -267.44168)
		(end 58.615072 -267.420852)
		(width 0.101854)
		(layer "F.Cu")
		(net "M_A_CPU1_SA_CS_N<0>")
	)
	(segment
		(start 53.403246 -267.866622)
		(end 54.480206 -267.866622)
		(width 0.20066)
		(layer "F.Cu")
		(net "M_A_CPU1_SA_CS_N<0>")
	)
	(segment
		(start 58.864246 -267.420852)
		(end 59.727592 -268.284198)
		(width 0.20066)
		(layer "F.Cu")
		(net "M_A_CPU1_SA_CS_N<0>")
	)
	(segment
		(start 58.668412 -267.420852)
		(end 58.864246 -267.420852)
		(width 0.20066)
		(layer "F.Cu")
		(net "M_A_CPU1_SA_CS_N<0>")
	)
	(segment
		(start 84.21878 -259.49148)
		(end 85.064092 -259.49148)
		(width 0.088646)
		(layer "F.Cu")
		(net "M_A_CPU1_SA_CS_N<0>")
	)
	(segment
		(start 66.35496 -268.291564)
		(end 66.412872 -268.291564)
		(width 0.101854)
		(layer "F.Cu")
		(net "M_A_CPU1_SA_CS_N<0>")
	)
	(segment
		(start 59.863736 -268.291564)
		(end 62.041532 -268.291564)
		(width 0.1016)
		(layer "F.Cu")
		(net "M_A_CPU1_SA_CS_N<0>")
	)
	(segment
		(start 77.955648 -262.36295)
		(end 78.307438 -262.01116)
		(width 0.20066)
		(layer "F.Cu")
		(net "M_A_CPU1_SA_CS_N<0>")
	)
	(segment
		(start 68.381372 -268.291564)
		(end 69.51218 -267.822426)
		(width 0.20066)
		(layer "F.Cu")
		(net "M_A_CPU1_SA_CS_N<0>")
	)
	(segment
		(start 85.064092 -259.49148)
		(end 85.474556 -259.081016)
		(width 0.088646)
		(layer "F.Cu")
		(net "M_A_CPU1_SA_CS_N<0>")
	)
	(segment
		(start 85.474556 -259.081016)
		(end 85.905594 -259.081016)
		(width 0.088646)
		(layer "F.Cu")
		(net "M_A_CPU1_SA_CS_N<0>")
	)
	(segment
		(start 72.861424 -264.473182)
		(end 77.955648 -262.36295)
		(width 0.20066)
		(layer "F.Cu")
		(net "M_A_CPU1_SA_CS_N<0>")
	)
	(segment
		(start 78.309978 -262.010144)
		(end 80.405478 -259.914644)
		(width 0.20066)
		(layer "F.Cu")
		(net "M_A_CPU1_SA_CS_N<0>")
	)
	(segment
		(start 62.097412 -268.27099)
		(end 62.372494 -268.27099)
		(width 0.20066)
		(layer "F.Cu")
		(net "M_A_CPU1_SA_CS_N<0>")
	)
	(segment
		(start 66.412872 -268.291564)
		(end 68.381372 -268.291564)
		(width 0.20066)
		(layer "F.Cu")
		(net "M_A_CPU1_SA_CS_N<0>")
	)
	(segment
		(start 67.317874 -269.359634)
		(end 67.117214 -269.560294)
		(width 0.20066)
		(layer "F.Cu")
		(net "M_A_CPU1_SA_CB<7>")
	)
	(segment
		(start 62.57925 -270.756126)
		(end 62.57925 -270.329152)
		(width 0.20066)
		(layer "F.Cu")
		(net "M_A_CPU1_SA_CB<7>")
	)
	(segment
		(start 73.388474 -265.564366)
		(end 69.643244 -269.309596)
		(width 0.20066)
		(layer "F.Cu")
		(net "M_A_CPU1_SA_CB<7>")
	)
	(segment
		(start 66.916554 -270.074898)
		(end 66.672714 -270.074898)
		(width 0.20066)
		(layer "F.Cu")
		(net "M_A_CPU1_SA_CB<7>")
	)
	(segment
		(start 68.7451 -269.701264)
		(end 68.856352 -269.812516)
		(width 0.20066)
		(layer "F.Cu")
		(net "M_A_CPU1_SA_CB<7>")
	)
	(segment
		(start 67.627754 -269.359634)
		(end 67.317874 -269.359634)
		(width 0.20066)
		(layer "F.Cu")
		(net "M_A_CPU1_SA_CB<7>")
	)
	(segment
		(start 85.24113 -260.454394)
		(end 85.24113 -260.346952)
		(width 0.088646)
		(layer "F.Cu")
		(net "M_A_CPU1_SA_CB<7>")
	)
	(segment
		(start 67.828414 -270.06931)
		(end 67.828414 -269.560294)
		(width 0.20066)
		(layer "F.Cu")
		(net "M_A_CPU1_SA_CB<7>")
	)
	(segment
		(start 81.720944 -260.65353)
		(end 76.186284 -266.18819)
		(width 0.1016)
		(layer "F.Cu")
		(net "M_A_CPU1_SA_CB<7>")
	)
	(segment
		(start 83.871054 -260.65353)
		(end 83.39455 -260.65353)
		(width 0.088646)
		(layer "F.Cu")
		(net "M_A_CPU1_SA_CB<7>")
	)
	(segment
		(start 84.271866 -260.047994)
		(end 84.11718 -260.20268)
		(width 0.088646)
		(layer "F.Cu")
		(net "M_A_CPU1_SA_CB<7>")
	)
	(segment
		(start 75.649836 -265.927586)
		(end 75.649836 -265.464798)
		(width 0.1016)
		(layer "F.Cu")
		(net "M_A_CPU1_SA_CB<7>")
	)
	(segment
		(start 68.7451 -269.417292)
		(end 68.7451 -269.701264)
		(width 0.20066)
		(layer "F.Cu")
		(net "M_A_CPU1_SA_CB<7>")
	)
	(segment
		(start 59.472068 -270.841724)
		(end 59.69635 -270.841724)
		(width 0.20066)
		(layer "F.Cu")
		(net "M_A_CPU1_SA_CB<7>")
	)
	(segment
		(start 85.519768 -260.51891)
		(end 85.305646 -260.51891)
		(width 0.088646)
		(layer "F.Cu")
		(net "M_A_CPU1_SA_CB<7>")
	)
	(segment
		(start 64.219582 -270.416782)
		(end 65.047114 -270.416782)
		(width 0.20066)
		(layer "F.Cu")
		(net "M_A_CPU1_SA_CB<7>")
	)
	(segment
		(start 59.314842 -270.684498)
		(end 59.472068 -270.841724)
		(width 0.20066)
		(layer "F.Cu")
		(net "M_A_CPU1_SA_CB<7>")
	)
	(segment
		(start 67.117214 -269.874238)
		(end 66.916554 -270.074898)
		(width 0.20066)
		(layer "F.Cu")
		(net "M_A_CPU1_SA_CB<7>")
	)
	(segment
		(start 67.117214 -269.560294)
		(end 67.117214 -269.874238)
		(width 0.20066)
		(layer "F.Cu")
		(net "M_A_CPU1_SA_CB<7>")
	)
	(segment
		(start 63.356236 -270.067278)
		(end 63.581788 -270.29283)
		(width 0.20066)
		(layer "F.Cu")
		(net "M_A_CPU1_SA_CB<7>")
	)
	(segment
		(start 76.186284 -266.18819)
		(end 75.91044 -266.18819)
		(width 0.1016)
		(layer "F.Cu")
		(net "M_A_CPU1_SA_CB<7>")
	)
	(segment
		(start 75.649836 -265.464798)
		(end 75.612752 -265.427714)
		(width 0.1016)
		(layer "F.Cu")
		(net "M_A_CPU1_SA_CB<7>")
	)
	(segment
		(start 69.359272 -269.309596)
		(end 69.24802 -269.198344)
		(width 0.20066)
		(layer "F.Cu")
		(net "M_A_CPU1_SA_CB<7>")
	)
	(segment
		(start 62.57925 -270.329152)
		(end 62.841124 -270.067278)
		(width 0.20066)
		(layer "F.Cu")
		(net "M_A_CPU1_SA_CB<7>")
	)
	(segment
		(start 65.529206 -270.416782)
		(end 65.047114 -270.416782)
		(width 0.20066)
		(layer "F.Cu")
		(net "M_A_CPU1_SA_CB<7>")
	)
	(segment
		(start 66.672714 -270.074898)
		(end 66.331084 -270.416528)
		(width 0.20066)
		(layer "F.Cu")
		(net "M_A_CPU1_SA_CB<7>")
	)
	(segment
		(start 83.39455 -260.65353)
		(end 81.720944 -260.65353)
		(width 0.1016)
		(layer "F.Cu")
		(net "M_A_CPU1_SA_CB<7>")
	)
	(segment
		(start 62.841124 -270.067278)
		(end 63.356236 -270.067278)
		(width 0.20066)
		(layer "F.Cu")
		(net "M_A_CPU1_SA_CB<7>")
	)
	(segment
		(start 67.828414 -269.560294)
		(end 67.627754 -269.359634)
		(width 0.20066)
		(layer "F.Cu")
		(net "M_A_CPU1_SA_CB<7>")
	)
	(segment
		(start 75.612752 -265.427714)
		(end 75.327764 -265.142726)
		(width 0.20066)
		(layer "F.Cu")
		(net "M_A_CPU1_SA_CB<7>")
	)
	(segment
		(start 69.24802 -269.198344)
		(end 68.964048 -269.198344)
		(width 0.20066)
		(layer "F.Cu")
		(net "M_A_CPU1_SA_CB<7>")
	)
	(segment
		(start 85.305646 -260.51891)
		(end 85.24113 -260.454394)
		(width 0.088646)
		(layer "F.Cu")
		(net "M_A_CPU1_SA_CB<7>")
	)
	(segment
		(start 66.331084 -270.416528)
		(end 65.52946 -270.416528)
		(width 0.20066)
		(layer "F.Cu")
		(net "M_A_CPU1_SA_CB<7>")
	)
	(segment
		(start 74.406252 -265.142726)
		(end 73.388474 -265.564366)
		(width 0.20066)
		(layer "F.Cu")
		(net "M_A_CPU1_SA_CB<7>")
	)
	(segment
		(start 84.11718 -260.407404)
		(end 83.871054 -260.65353)
		(width 0.088646)
		(layer "F.Cu")
		(net "M_A_CPU1_SA_CB<7>")
	)
	(segment
		(start 75.91044 -266.18819)
		(end 75.649836 -265.927586)
		(width 0.1016)
		(layer "F.Cu")
		(net "M_A_CPU1_SA_CB<7>")
	)
	(segment
		(start 87.275924 -260.708902)
		(end 87.351108 -260.633718)
		(width 0.088646)
		(layer "F.Cu")
		(net "M_A_CPU1_SA_CB<7>")
	)
	(segment
		(start 68.68287 -270.26997)
		(end 68.029074 -270.26997)
		(width 0.20066)
		(layer "F.Cu")
		(net "M_A_CPU1_SA_CB<7>")
	)
	(segment
		(start 59.314842 -270.542512)
		(end 59.314842 -270.684498)
		(width 0.20066)
		(layer "F.Cu")
		(net "M_A_CPU1_SA_CB<7>")
	)
	(segment
		(start 59.69635 -270.841724)
		(end 59.840876 -270.841724)
		(width 0.101854)
		(layer "F.Cu")
		(net "M_A_CPU1_SA_CB<7>")
	)
	(segment
		(start 62.493652 -270.841724)
		(end 62.57925 -270.756126)
		(width 0.20066)
		(layer "F.Cu")
		(net "M_A_CPU1_SA_CB<7>")
	)
	(segment
		(start 64.09563 -270.29283)
		(end 64.219582 -270.416782)
		(width 0.20066)
		(layer "F.Cu")
		(net "M_A_CPU1_SA_CB<7>")
	)
	(segment
		(start 68.029074 -270.26997)
		(end 67.828414 -270.06931)
		(width 0.20066)
		(layer "F.Cu")
		(net "M_A_CPU1_SA_CB<7>")
	)
	(segment
		(start 62.217046 -270.841724)
		(end 62.493652 -270.841724)
		(width 0.20066)
		(layer "F.Cu")
		(net "M_A_CPU1_SA_CB<7>")
	)
	(segment
		(start 87.351108 -260.3373)
		(end 87.27186 -260.258052)
		(width 0.088646)
		(layer "F.Cu")
		(net "M_A_CPU1_SA_CB<7>")
	)
	(segment
		(start 59.840876 -270.841724)
		(end 62.122812 -270.841724)
		(width 0.1016)
		(layer "F.Cu")
		(net "M_A_CPU1_SA_CB<7>")
	)
	(segment
		(start 84.942172 -260.047994)
		(end 84.271866 -260.047994)
		(width 0.088646)
		(layer "F.Cu")
		(net "M_A_CPU1_SA_CB<7>")
	)
	(segment
		(start 68.856352 -270.096488)
		(end 68.68287 -270.26997)
		(width 0.20066)
		(layer "F.Cu")
		(net "M_A_CPU1_SA_CB<7>")
	)
	(segment
		(start 85.780626 -260.258052)
		(end 85.519768 -260.51891)
		(width 0.088646)
		(layer "F.Cu")
		(net "M_A_CPU1_SA_CB<7>")
	)
	(segment
		(start 85.24113 -260.346952)
		(end 84.942172 -260.047994)
		(width 0.088646)
		(layer "F.Cu")
		(net "M_A_CPU1_SA_CB<7>")
	)
	(segment
		(start 63.581788 -270.29283)
		(end 64.09563 -270.29283)
		(width 0.20066)
		(layer "F.Cu")
		(net "M_A_CPU1_SA_CB<7>")
	)
	(segment
		(start 87.351108 -260.633718)
		(end 87.351108 -260.3373)
		(width 0.088646)
		(layer "F.Cu")
		(net "M_A_CPU1_SA_CB<7>")
	)
	(segment
		(start 75.327764 -265.142726)
		(end 74.406252 -265.142726)
		(width 0.20066)
		(layer "F.Cu")
		(net "M_A_CPU1_SA_CB<7>")
	)
	(segment
		(start 57.503314 -270.416782)
		(end 59.188604 -270.416782)
		(width 0.20066)
		(layer "F.Cu")
		(net "M_A_CPU1_SA_CB<7>")
	)
	(segment
		(start 62.122812 -270.841724)
		(end 62.217046 -270.841724)
		(width 0.101854)
		(layer "F.Cu")
		(net "M_A_CPU1_SA_CB<7>")
	)
	(segment
		(start 68.856352 -269.812516)
		(end 68.856352 -270.096488)
		(width 0.20066)
		(layer "F.Cu")
		(net "M_A_CPU1_SA_CB<7>")
	)
	(segment
		(start 69.643244 -269.309596)
		(end 69.359272 -269.309596)
		(width 0.20066)
		(layer "F.Cu")
		(net "M_A_CPU1_SA_CB<7>")
	)
	(segment
		(start 59.188604 -270.416782)
		(end 59.188858 -270.416528)
		(width 0.20066)
		(layer "F.Cu")
		(net "M_A_CPU1_SA_CB<7>")
	)
	(segment
		(start 87.27186 -260.258052)
		(end 85.780626 -260.258052)
		(width 0.088646)
		(layer "F.Cu")
		(net "M_A_CPU1_SA_CB<7>")
	)
	(segment
		(start 65.52946 -270.416528)
		(end 65.529206 -270.416782)
		(width 0.20066)
		(layer "F.Cu")
		(net "M_A_CPU1_SA_CB<7>")
	)
	(segment
		(start 86.845648 -260.708902)
		(end 87.275924 -260.708902)
		(width 0.088646)
		(layer "F.Cu")
		(net "M_A_CPU1_SA_CB<7>")
	)
	(segment
		(start 68.964048 -269.198344)
		(end 68.7451 -269.417292)
		(width 0.20066)
		(layer "F.Cu")
		(net "M_A_CPU1_SA_CB<7>")
	)
	(segment
		(start 59.188858 -270.416528)
		(end 59.314842 -270.542512)
		(width 0.20066)
		(layer "F.Cu")
		(net "M_A_CPU1_SA_CB<7>")
	)
	(segment
		(start 84.11718 -260.20268)
		(end 84.11718 -260.407404)
		(width 0.088646)
		(layer "F.Cu")
		(net "M_A_CPU1_SA_CB<7>")
	)
	(segment
		(start 67.865244 -272.903696)
		(end 67.442842 -272.903696)
		(width 0.20066)
		(layer "F.Cu")
		(net "M_A_CPU1_SA_CB<6>")
	)
	(segment
		(start 74.60234 -266.575794)
		(end 73.90384 -266.8651)
		(width 0.20066)
		(layer "F.Cu")
		(net "M_A_CPU1_SA_CB<6>")
	)
	(segment
		(start 62.951614 -272.245074)
		(end 63.080138 -272.11655)
		(width 0.20066)
		(layer "F.Cu")
		(net "M_A_CPU1_SA_CB<6>")
	)
	(segment
		(start 86.192868 -261.015226)
		(end 86.065868 -261.142226)
		(width 0.088646)
		(layer "F.Cu")
		(net "M_A_CPU1_SA_CB<6>")
	)
	(segment
		(start 86.999826 -261.119366)
		(end 86.999826 -261.238746)
		(width 0.088646)
		(layer "F.Cu")
		(net "M_A_CPU1_SA_CB<6>")
	)
	(segment
		(start 63.080392 -272.116804)
		(end 65.047114 -272.116804)
		(width 0.20066)
		(layer "F.Cu")
		(net "M_A_CPU1_SA_CB<6>")
	)
	(segment
		(start 87.41918 -260.98373)
		(end 87.340186 -260.904736)
		(width 0.088646)
		(layer "F.Cu")
		(net "M_A_CPU1_SA_CB<6>")
	)
	(segment
		(start 62.51702 -271.832324)
		(end 62.51702 -272.0721)
		(width 0.20066)
		(layer "F.Cu")
		(net "M_A_CPU1_SA_CB<6>")
	)
	(segment
		(start 67.82054 -272.040604)
		(end 68.114164 -272.334228)
		(width 0.20066)
		(layer "F.Cu")
		(net "M_A_CPU1_SA_CB<6>")
	)
	(segment
		(start 60.022232 -271.675098)
		(end 60.076334 -271.691608)
		(width 0.1016)
		(layer "F.Cu")
		(net "M_A_CPU1_SA_CB<6>")
	)
	(segment
		(start 84.055966 -261.499096)
		(end 83.944968 -261.388098)
		(width 0.088646)
		(layer "F.Cu")
		(net "M_A_CPU1_SA_CB<6>")
	)
	(segment
		(start 75.481688 -266.908026)
		(end 75.43673 -266.863068)
		(width 0.1016)
		(layer "F.Cu")
		(net "M_A_CPU1_SA_CB<6>")
	)
	(segment
		(start 59.00039 -272.116804)
		(end 59.102752 -272.014442)
		(width 0.20066)
		(layer "F.Cu")
		(net "M_A_CPU1_SA_CB<6>")
	)
	(segment
		(start 87.315294 -261.522718)
		(end 87.315294 -261.212838)
		(width 0.088646)
		(layer "F.Cu")
		(net "M_A_CPU1_SA_CB<6>")
	)
	(segment
		(start 85.060536 -261.305802)
		(end 84.440776 -261.305802)
		(width 0.088646)
		(layer "F.Cu")
		(net "M_A_CPU1_SA_CB<6>")
	)
	(segment
		(start 81.973928 -261.263638)
		(end 76.32954 -266.908026)
		(width 0.1016)
		(layer "F.Cu")
		(net "M_A_CPU1_SA_CB<6>")
	)
	(segment
		(start 86.999826 -261.238746)
		(end 86.90737 -261.331202)
		(width 0.088646)
		(layer "F.Cu")
		(net "M_A_CPU1_SA_CB<6>")
	)
	(segment
		(start 85.67674 -261.083298)
		(end 85.676232 -261.083298)
		(width 0.088646)
		(layer "F.Cu")
		(net "M_A_CPU1_SA_CB<6>")
	)
	(segment
		(start 86.781386 -261.331202)
		(end 86.695026 -261.244842)
		(width 0.088646)
		(layer "F.Cu")
		(net "M_A_CPU1_SA_CB<6>")
	)
	(segment
		(start 67.242182 -272.703036)
		(end 67.242182 -272.542762)
		(width 0.20066)
		(layer "F.Cu")
		(net "M_A_CPU1_SA_CB<6>")
	)
	(segment
		(start 85.976968 -261.37743)
		(end 85.851238 -261.37743)
		(width 0.088646)
		(layer "F.Cu")
		(net "M_A_CPU1_SA_CB<6>")
	)
	(segment
		(start 57.503314 -272.116804)
		(end 59.00039 -272.116804)
		(width 0.20066)
		(layer "F.Cu")
		(net "M_A_CPU1_SA_CB<6>")
	)
	(segment
		(start 59.25947 -271.675098)
		(end 59.688476 -271.675098)
		(width 0.20066)
		(layer "F.Cu")
		(net "M_A_CPU1_SA_CB<6>")
	)
	(segment
		(start 83.944968 -261.388098)
		(end 83.820508 -261.263638)
		(width 0.1016)
		(layer "F.Cu")
		(net "M_A_CPU1_SA_CB<6>")
	)
	(segment
		(start 62.376304 -271.691608)
		(end 62.51702 -271.832324)
		(width 0.20066)
		(layer "F.Cu")
		(net "M_A_CPU1_SA_CB<6>")
	)
	(segment
		(start 84.247482 -261.499096)
		(end 84.055966 -261.499096)
		(width 0.088646)
		(layer "F.Cu")
		(net "M_A_CPU1_SA_CB<6>")
	)
	(segment
		(start 87.214456 -260.904736)
		(end 86.999826 -261.119366)
		(width 0.088646)
		(layer "F.Cu")
		(net "M_A_CPU1_SA_CB<6>")
	)
	(segment
		(start 87.41918 -261.108952)
		(end 87.41918 -260.98373)
		(width 0.088646)
		(layer "F.Cu")
		(net "M_A_CPU1_SA_CB<6>")
	)
	(segment
		(start 68.0212 -271.555972)
		(end 67.82054 -271.756632)
		(width 0.20066)
		(layer "F.Cu")
		(net "M_A_CPU1_SA_CB<6>")
	)
	(segment
		(start 62.209172 -271.691608)
		(end 62.376304 -271.691608)
		(width 0.20066)
		(layer "F.Cu")
		(net "M_A_CPU1_SA_CB<6>")
	)
	(segment
		(start 63.080138 -272.11655)
		(end 63.080392 -272.116804)
		(width 0.20066)
		(layer "F.Cu")
		(net "M_A_CPU1_SA_CB<6>")
	)
	(segment
		(start 86.695026 -261.244842)
		(end 86.695026 -261.142226)
		(width 0.088646)
		(layer "F.Cu")
		(net "M_A_CPU1_SA_CB<6>")
	)
	(segment
		(start 67.242182 -272.542762)
		(end 66.81597 -272.11655)
		(width 0.20066)
		(layer "F.Cu")
		(net "M_A_CPU1_SA_CB<6>")
	)
	(segment
		(start 85.851238 -261.37743)
		(end 85.76564 -261.291832)
		(width 0.088646)
		(layer "F.Cu")
		(net "M_A_CPU1_SA_CB<6>")
	)
	(segment
		(start 66.661284 -272.11655)
		(end 66.660522 -272.116804)
		(width 0.20066)
		(layer "F.Cu")
		(net "M_A_CPU1_SA_CB<6>")
	)
	(segment
		(start 86.90737 -261.331202)
		(end 86.781386 -261.331202)
		(width 0.088646)
		(layer "F.Cu")
		(net "M_A_CPU1_SA_CB<6>")
	)
	(segment
		(start 75.43673 -266.677648)
		(end 75.334876 -266.575794)
		(width 0.1016)
		(layer "F.Cu")
		(net "M_A_CPU1_SA_CB<6>")
	)
	(segment
		(start 60.076334 -271.691608)
		(end 62.122812 -271.691608)
		(width 0.1016)
		(layer "F.Cu")
		(net "M_A_CPU1_SA_CB<6>")
	)
	(segment
		(start 66.660522 -272.116804)
		(end 65.047114 -272.116804)
		(width 0.20066)
		(layer "F.Cu")
		(net "M_A_CPU1_SA_CB<6>")
	)
	(segment
		(start 86.065868 -261.28853)
		(end 85.976968 -261.37743)
		(width 0.088646)
		(layer "F.Cu")
		(net "M_A_CPU1_SA_CB<6>")
	)
	(segment
		(start 59.102752 -272.014442)
		(end 59.102752 -271.831816)
		(width 0.20066)
		(layer "F.Cu")
		(net "M_A_CPU1_SA_CB<6>")
	)
	(segment
		(start 68.114164 -272.334228)
		(end 68.114164 -272.654776)
		(width 0.20066)
		(layer "F.Cu")
		(net "M_A_CPU1_SA_CB<6>")
	)
	(segment
		(start 62.689994 -272.245074)
		(end 62.951614 -272.245074)
		(width 0.20066)
		(layer "F.Cu")
		(net "M_A_CPU1_SA_CB<6>")
	)
	(segment
		(start 68.617084 -271.867884)
		(end 68.305172 -271.555972)
		(width 0.20066)
		(layer "F.Cu")
		(net "M_A_CPU1_SA_CB<6>")
	)
	(segment
		(start 85.76564 -261.291832)
		(end 85.76564 -261.172198)
		(width 0.088646)
		(layer "F.Cu")
		(net "M_A_CPU1_SA_CB<6>")
	)
	(segment
		(start 67.442842 -272.903696)
		(end 67.242182 -272.703036)
		(width 0.20066)
		(layer "F.Cu")
		(net "M_A_CPU1_SA_CB<6>")
	)
	(segment
		(start 67.82054 -271.756632)
		(end 67.82054 -272.040604)
		(width 0.20066)
		(layer "F.Cu")
		(net "M_A_CPU1_SA_CB<6>")
	)
	(segment
		(start 86.568026 -261.015226)
		(end 86.192868 -261.015226)
		(width 0.088646)
		(layer "F.Cu")
		(net "M_A_CPU1_SA_CB<6>")
	)
	(segment
		(start 86.065868 -261.142226)
		(end 86.065868 -261.28853)
		(width 0.088646)
		(layer "F.Cu")
		(net "M_A_CPU1_SA_CB<6>")
	)
	(segment
		(start 84.440776 -261.305802)
		(end 84.247482 -261.499096)
		(width 0.088646)
		(layer "F.Cu")
		(net "M_A_CPU1_SA_CB<6>")
	)
	(segment
		(start 68.114164 -272.654776)
		(end 67.865244 -272.903696)
		(width 0.20066)
		(layer "F.Cu")
		(net "M_A_CPU1_SA_CB<6>")
	)
	(segment
		(start 86.695026 -261.142226)
		(end 86.568026 -261.015226)
		(width 0.088646)
		(layer "F.Cu")
		(net "M_A_CPU1_SA_CB<6>")
	)
	(segment
		(start 85.246972 -261.19836)
		(end 85.060536 -261.305802)
		(width 0.088646)
		(layer "F.Cu")
		(net "M_A_CPU1_SA_CB<6>")
	)
	(segment
		(start 87.315294 -261.212838)
		(end 87.41918 -261.108952)
		(width 0.088646)
		(layer "F.Cu")
		(net "M_A_CPU1_SA_CB<6>")
	)
	(segment
		(start 75.334876 -266.575794)
		(end 75.081384 -266.575794)
		(width 0.1016)
		(layer "F.Cu")
		(net "M_A_CPU1_SA_CB<6>")
	)
	(segment
		(start 75.43673 -266.863068)
		(end 75.43673 -266.677648)
		(width 0.1016)
		(layer "F.Cu")
		(net "M_A_CPU1_SA_CB<6>")
	)
	(segment
		(start 59.688476 -271.675098)
		(end 60.022232 -271.675098)
		(width 0.101854)
		(layer "F.Cu")
		(net "M_A_CPU1_SA_CB<6>")
	)
	(segment
		(start 83.820508 -261.263638)
		(end 81.973928 -261.263638)
		(width 0.1016)
		(layer "F.Cu")
		(net "M_A_CPU1_SA_CB<6>")
	)
	(segment
		(start 62.51702 -272.0721)
		(end 62.689994 -272.245074)
		(width 0.20066)
		(layer "F.Cu")
		(net "M_A_CPU1_SA_CB<6>")
	)
	(segment
		(start 68.305172 -271.555972)
		(end 68.0212 -271.555972)
		(width 0.20066)
		(layer "F.Cu")
		(net "M_A_CPU1_SA_CB<6>")
	)
	(segment
		(start 59.102752 -271.831816)
		(end 59.25947 -271.675098)
		(width 0.20066)
		(layer "F.Cu")
		(net "M_A_CPU1_SA_CB<6>")
	)
	(segment
		(start 62.122812 -271.691608)
		(end 62.209172 -271.691608)
		(width 0.101854)
		(layer "F.Cu")
		(net "M_A_CPU1_SA_CB<6>")
	)
	(segment
		(start 66.81597 -272.11655)
		(end 66.661284 -272.11655)
		(width 0.20066)
		(layer "F.Cu")
		(net "M_A_CPU1_SA_CB<6>")
	)
	(segment
		(start 68.901056 -271.867884)
		(end 68.617084 -271.867884)
		(width 0.20066)
		(layer "F.Cu")
		(net "M_A_CPU1_SA_CB<6>")
	)
	(segment
		(start 85.76564 -261.172198)
		(end 85.67674 -261.083298)
		(width 0.088646)
		(layer "F.Cu")
		(net "M_A_CPU1_SA_CB<6>")
	)
	(segment
		(start 75.081384 -266.575794)
		(end 74.60234 -266.575794)
		(width 0.20066)
		(layer "F.Cu")
		(net "M_A_CPU1_SA_CB<6>")
	)
	(segment
		(start 76.32954 -266.908026)
		(end 75.481688 -266.908026)
		(width 0.1016)
		(layer "F.Cu")
		(net "M_A_CPU1_SA_CB<6>")
	)
	(segment
		(start 87.340186 -260.904736)
		(end 87.214456 -260.904736)
		(width 0.088646)
		(layer "F.Cu")
		(net "M_A_CPU1_SA_CB<6>")
	)
	(segment
		(start 73.90384 -266.8651)
		(end 68.901056 -271.867884)
		(width 0.20066)
		(layer "F.Cu")
		(net "M_A_CPU1_SA_CB<6>")
	)
	(arc
		(start 85.676232 -261.083298)
		(mid 85.45402 -261.112554)
		(end 85.246972 -261.19836)
		(width 0.088646)
		(layer "F.Cu")
		(net "M_A_CPU1_SA_CB<6>")
	)
	(segment
		(start 62.827662 -271.266666)
		(end 60.947046 -271.266666)
		(width 0.20066)
		(layer "F.Cu")
		(net "M_A_CPU1_SA_CB<5>")
	)
	(segment
		(start 75.157076 -265.88339)
		(end 75.075542 -265.801856)
		(width 0.20066)
		(layer "F.Cu")
		(net "M_A_CPU1_SA_CB<5>")
	)
	(segment
		(start 67.75069 -270.914876)
		(end 67.550792 -270.714978)
		(width 0.20066)
		(layer "F.Cu")
		(net "M_A_CPU1_SA_CB<5>")
	)
	(segment
		(start 85.00999 -261.115302)
		(end 84.142072 -261.115302)
		(width 0.088646)
		(layer "F.Cu")
		(net "M_A_CPU1_SA_CB<5>")
	)
	(segment
		(start 85.905594 -260.708902)
		(end 85.905594 -260.708648)
		(width 0.088646)
		(layer "F.Cu")
		(net "M_A_CPU1_SA_CB<5>")
	)
	(segment
		(start 85.5472 -260.80466)
		(end 85.00999 -261.115302)
		(width 0.088646)
		(layer "F.Cu")
		(net "M_A_CPU1_SA_CB<5>")
	)
	(segment
		(start 55.535068 -270.71193)
		(end 55.664862 -270.841724)
		(width 0.20066)
		(layer "F.Cu")
		(net "M_A_CPU1_SA_CB<5>")
	)
	(segment
		(start 63.580518 -271.691608)
		(end 63.252604 -271.691608)
		(width 0.20066)
		(layer "F.Cu")
		(net "M_A_CPU1_SA_CB<5>")
	)
	(segment
		(start 66.511932 -271.691608)
		(end 66.122042 -271.691608)
		(width 0.101854)
		(layer "F.Cu")
		(net "M_A_CPU1_SA_CB<5>")
	)
	(segment
		(start 54.340506 -271.386554)
		(end 54.87162 -271.386554)
		(width 0.20066)
		(layer "F.Cu")
		(net "M_A_CPU1_SA_CB<5>")
	)
	(segment
		(start 54.87162 -271.386554)
		(end 55.05196 -271.206214)
		(width 0.20066)
		(layer "F.Cu")
		(net "M_A_CPU1_SA_CB<5>")
	)
	(segment
		(start 66.82232 -271.441164)
		(end 66.571876 -271.691608)
		(width 0.20066)
		(layer "F.Cu")
		(net "M_A_CPU1_SA_CB<5>")
	)
	(segment
		(start 83.985354 -260.958584)
		(end 83.39455 -260.958584)
		(width 0.088646)
		(layer "F.Cu")
		(net "M_A_CPU1_SA_CB<5>")
	)
	(segment
		(start 53.403246 -271.266666)
		(end 54.220618 -271.266666)
		(width 0.20066)
		(layer "F.Cu")
		(net "M_A_CPU1_SA_CB<5>")
	)
	(segment
		(start 73.561956 -266.296648)
		(end 68.943728 -270.914876)
		(width 0.20066)
		(layer "F.Cu")
		(net "M_A_CPU1_SA_CB<5>")
	)
	(segment
		(start 75.866752 -266.593066)
		(end 75.157076 -265.88339)
		(width 0.1016)
		(layer "F.Cu")
		(net "M_A_CPU1_SA_CB<5>")
	)
	(segment
		(start 58.881264 -270.841724)
		(end 59.306206 -271.266666)
		(width 0.20066)
		(layer "F.Cu")
		(net "M_A_CPU1_SA_CB<5>")
	)
	(segment
		(start 55.664862 -270.841724)
		(end 56.256936 -270.841724)
		(width 0.20066)
		(layer "F.Cu")
		(net "M_A_CPU1_SA_CB<5>")
	)
	(segment
		(start 58.668412 -270.841724)
		(end 58.757566 -270.841724)
		(width 0.101854)
		(layer "F.Cu")
		(net "M_A_CPU1_SA_CB<5>")
	)
	(segment
		(start 56.256936 -270.841724)
		(end 56.633364 -270.841724)
		(width 0.101854)
		(layer "F.Cu")
		(net "M_A_CPU1_SA_CB<5>")
	)
	(segment
		(start 66.82232 -270.915892)
		(end 66.82232 -271.441164)
		(width 0.20066)
		(layer "F.Cu")
		(net "M_A_CPU1_SA_CB<5>")
	)
	(segment
		(start 67.023234 -270.714978)
		(end 66.82232 -270.915892)
		(width 0.20066)
		(layer "F.Cu")
		(net "M_A_CPU1_SA_CB<5>")
	)
	(segment
		(start 58.757566 -270.841724)
		(end 58.881264 -270.841724)
		(width 0.20066)
		(layer "F.Cu")
		(net "M_A_CPU1_SA_CB<5>")
	)
	(segment
		(start 68.943728 -270.914876)
		(end 67.75069 -270.914876)
		(width 0.20066)
		(layer "F.Cu")
		(net "M_A_CPU1_SA_CB<5>")
	)
	(segment
		(start 55.05196 -270.899636)
		(end 55.239666 -270.71193)
		(width 0.20066)
		(layer "F.Cu")
		(net "M_A_CPU1_SA_CB<5>")
	)
	(segment
		(start 66.122042 -271.691608)
		(end 64.075564 -271.691608)
		(width 0.1016)
		(layer "F.Cu")
		(net "M_A_CPU1_SA_CB<5>")
	)
	(segment
		(start 55.05196 -271.206214)
		(end 55.05196 -270.899636)
		(width 0.20066)
		(layer "F.Cu")
		(net "M_A_CPU1_SA_CB<5>")
	)
	(segment
		(start 81.847436 -260.958584)
		(end 76.212954 -266.593066)
		(width 0.1016)
		(layer "F.Cu")
		(net "M_A_CPU1_SA_CB<5>")
	)
	(segment
		(start 63.252604 -271.691608)
		(end 62.827662 -271.266666)
		(width 0.20066)
		(layer "F.Cu")
		(net "M_A_CPU1_SA_CB<5>")
	)
	(segment
		(start 55.239666 -270.71193)
		(end 55.535068 -270.71193)
		(width 0.20066)
		(layer "F.Cu")
		(net "M_A_CPU1_SA_CB<5>")
	)
	(segment
		(start 56.633364 -270.841724)
		(end 58.668412 -270.841724)
		(width 0.1016)
		(layer "F.Cu")
		(net "M_A_CPU1_SA_CB<5>")
	)
	(segment
		(start 64.075564 -271.691608)
		(end 63.580518 -271.691608)
		(width 0.101854)
		(layer "F.Cu")
		(net "M_A_CPU1_SA_CB<5>")
	)
	(segment
		(start 66.571876 -271.691608)
		(end 66.511932 -271.691608)
		(width 0.20066)
		(layer "F.Cu")
		(net "M_A_CPU1_SA_CB<5>")
	)
	(segment
		(start 76.212954 -266.593066)
		(end 75.866752 -266.593066)
		(width 0.1016)
		(layer "F.Cu")
		(net "M_A_CPU1_SA_CB<5>")
	)
	(segment
		(start 74.756264 -265.801856)
		(end 73.561956 -266.296648)
		(width 0.20066)
		(layer "F.Cu")
		(net "M_A_CPU1_SA_CB<5>")
	)
	(segment
		(start 54.220618 -271.266666)
		(end 54.340506 -271.386554)
		(width 0.20066)
		(layer "F.Cu")
		(net "M_A_CPU1_SA_CB<5>")
	)
	(segment
		(start 83.39455 -260.958584)
		(end 81.847436 -260.958584)
		(width 0.1016)
		(layer "F.Cu")
		(net "M_A_CPU1_SA_CB<5>")
	)
	(segment
		(start 75.075542 -265.801856)
		(end 74.756264 -265.801856)
		(width 0.20066)
		(layer "F.Cu")
		(net "M_A_CPU1_SA_CB<5>")
	)
	(segment
		(start 85.905594 -260.708648)
		(end 85.5472 -260.80466)
		(width 0.088646)
		(layer "F.Cu")
		(net "M_A_CPU1_SA_CB<5>")
	)
	(segment
		(start 84.142072 -261.115302)
		(end 83.985354 -260.958584)
		(width 0.088646)
		(layer "F.Cu")
		(net "M_A_CPU1_SA_CB<5>")
	)
	(segment
		(start 59.306206 -271.266666)
		(end 60.947046 -271.266666)
		(width 0.20066)
		(layer "F.Cu")
		(net "M_A_CPU1_SA_CB<5>")
	)
	(segment
		(start 67.550792 -270.714978)
		(end 67.023234 -270.714978)
		(width 0.20066)
		(layer "F.Cu")
		(net "M_A_CPU1_SA_CB<5>")
	)
	(segment
		(start 62.553596 -272.903696)
		(end 62.803532 -273.153632)
		(width 0.20066)
		(layer "F.Cu")
		(net "M_A_CPU1_SA_CB<4>")
	)
	(segment
		(start 83.079336 -261.568692)
		(end 83.190334 -261.67969)
		(width 0.088646)
		(layer "F.Cu")
		(net "M_A_CPU1_SA_CB<4>")
	)
	(segment
		(start 82.10042 -261.568692)
		(end 82.709004 -261.568692)
		(width 0.1016)
		(layer "F.Cu")
		(net "M_A_CPU1_SA_CB<4>")
	)
	(segment
		(start 59.230514 -272.541746)
		(end 59.531504 -272.842736)
		(width 0.20066)
		(layer "F.Cu")
		(net "M_A_CPU1_SA_CB<4>")
	)
	(segment
		(start 63.281052 -272.775172)
		(end 63.514478 -272.541746)
		(width 0.20066)
		(layer "F.Cu")
		(net "M_A_CPU1_SA_CB<4>")
	)
	(segment
		(start 66.818256 -272.742406)
		(end 66.818256 -273.319748)
		(width 0.20066)
		(layer "F.Cu")
		(net "M_A_CPU1_SA_CB<4>")
	)
	(segment
		(start 66.617596 -272.541746)
		(end 66.818256 -272.742406)
		(width 0.20066)
		(layer "F.Cu")
		(net "M_A_CPU1_SA_CB<4>")
	)
	(segment
		(start 55.11292 -272.214594)
		(end 55.396892 -272.214594)
		(width 0.20066)
		(layer "F.Cu")
		(net "M_A_CPU1_SA_CB<4>")
	)
	(segment
		(start 63.980314 -272.541746)
		(end 66.200274 -272.541746)
		(width 0.1016)
		(layer "F.Cu")
		(net "M_A_CPU1_SA_CB<4>")
	)
	(segment
		(start 74.753978 -267.220446)
		(end 75.081384 -267.220446)
		(width 0.20066)
		(layer "F.Cu")
		(net "M_A_CPU1_SA_CB<4>")
	)
	(segment
		(start 60.947046 -272.966688)
		(end 61.885576 -272.966688)
		(width 0.20066)
		(layer "F.Cu")
		(net "M_A_CPU1_SA_CB<4>")
	)
	(segment
		(start 83.701382 -261.568692)
		(end 83.861148 -261.728458)
		(width 0.088646)
		(layer "F.Cu")
		(net "M_A_CPU1_SA_CB<4>")
	)
	(segment
		(start 68.136008 -273.55419)
		(end 74.269092 -267.421106)
		(width 0.20066)
		(layer "F.Cu")
		(net "M_A_CPU1_SA_CB<4>")
	)
	(segment
		(start 76.448666 -267.220446)
		(end 82.10042 -261.568692)
		(width 0.1016)
		(layer "F.Cu")
		(net "M_A_CPU1_SA_CB<4>")
	)
	(segment
		(start 74.269092 -267.421106)
		(end 74.753978 -267.220446)
		(width 0.20066)
		(layer "F.Cu")
		(net "M_A_CPU1_SA_CB<4>")
	)
	(segment
		(start 54.247034 -272.966688)
		(end 54.36743 -273.087084)
		(width 0.20066)
		(layer "F.Cu")
		(net "M_A_CPU1_SA_CB<4>")
	)
	(segment
		(start 83.392518 -261.67969)
		(end 83.503516 -261.568692)
		(width 0.088646)
		(layer "F.Cu")
		(net "M_A_CPU1_SA_CB<4>")
	)
	(segment
		(start 55.396892 -272.214594)
		(end 55.724044 -272.541746)
		(width 0.20066)
		(layer "F.Cu")
		(net "M_A_CPU1_SA_CB<4>")
	)
	(segment
		(start 63.514478 -272.541746)
		(end 63.582296 -272.541746)
		(width 0.20066)
		(layer "F.Cu")
		(net "M_A_CPU1_SA_CB<4>")
	)
	(segment
		(start 61.885576 -272.966688)
		(end 62.172342 -272.903696)
		(width 0.20066)
		(layer "F.Cu")
		(net "M_A_CPU1_SA_CB<4>")
	)
	(segment
		(start 62.803532 -273.153632)
		(end 63.166752 -273.153632)
		(width 0.20066)
		(layer "F.Cu")
		(net "M_A_CPU1_SA_CB<4>")
	)
	(segment
		(start 54.36743 -273.087084)
		(end 54.671722 -273.087084)
		(width 0.20066)
		(layer "F.Cu")
		(net "M_A_CPU1_SA_CB<4>")
	)
	(segment
		(start 56.459374 -272.541746)
		(end 58.643012 -272.541746)
		(width 0.1016)
		(layer "F.Cu")
		(net "M_A_CPU1_SA_CB<4>")
	)
	(segment
		(start 83.190334 -261.67969)
		(end 83.392518 -261.67969)
		(width 0.088646)
		(layer "F.Cu")
		(net "M_A_CPU1_SA_CB<4>")
	)
	(segment
		(start 66.200274 -272.541746)
		(end 66.51371 -272.541746)
		(width 0.101854)
		(layer "F.Cu")
		(net "M_A_CPU1_SA_CB<4>")
	)
	(segment
		(start 59.969654 -272.842736)
		(end 60.093606 -272.966688)
		(width 0.20066)
		(layer "F.Cu")
		(net "M_A_CPU1_SA_CB<4>")
	)
	(segment
		(start 54.671722 -273.087084)
		(end 54.872382 -272.886424)
		(width 0.20066)
		(layer "F.Cu")
		(net "M_A_CPU1_SA_CB<4>")
	)
	(segment
		(start 63.582296 -272.541746)
		(end 63.980314 -272.541746)
		(width 0.101854)
		(layer "F.Cu")
		(net "M_A_CPU1_SA_CB<4>")
	)
	(segment
		(start 58.971688 -272.541746)
		(end 59.230514 -272.541746)
		(width 0.20066)
		(layer "F.Cu")
		(net "M_A_CPU1_SA_CB<4>")
	)
	(segment
		(start 55.724044 -272.541746)
		(end 56.044338 -272.541746)
		(width 0.20066)
		(layer "F.Cu")
		(net "M_A_CPU1_SA_CB<4>")
	)
	(segment
		(start 67.052698 -273.55419)
		(end 68.136008 -273.55419)
		(width 0.20066)
		(layer "F.Cu")
		(net "M_A_CPU1_SA_CB<4>")
	)
	(segment
		(start 59.531504 -272.842736)
		(end 59.969654 -272.842736)
		(width 0.20066)
		(layer "F.Cu")
		(net "M_A_CPU1_SA_CB<4>")
	)
	(segment
		(start 66.818256 -273.319748)
		(end 67.052698 -273.55419)
		(width 0.20066)
		(layer "F.Cu")
		(net "M_A_CPU1_SA_CB<4>")
	)
	(segment
		(start 62.172342 -272.903696)
		(end 62.553596 -272.903696)
		(width 0.20066)
		(layer "F.Cu")
		(net "M_A_CPU1_SA_CB<4>")
	)
	(segment
		(start 84.336636 -261.728458)
		(end 84.542376 -261.522718)
		(width 0.088646)
		(layer "F.Cu")
		(net "M_A_CPU1_SA_CB<4>")
	)
	(segment
		(start 82.709004 -261.568692)
		(end 83.079336 -261.568692)
		(width 0.088646)
		(layer "F.Cu")
		(net "M_A_CPU1_SA_CB<4>")
	)
	(segment
		(start 54.872382 -272.886424)
		(end 54.872382 -272.455132)
		(width 0.20066)
		(layer "F.Cu")
		(net "M_A_CPU1_SA_CB<4>")
	)
	(segment
		(start 63.166752 -273.153632)
		(end 63.281052 -273.039332)
		(width 0.20066)
		(layer "F.Cu")
		(net "M_A_CPU1_SA_CB<4>")
	)
	(segment
		(start 66.51371 -272.541746)
		(end 66.617596 -272.541746)
		(width 0.20066)
		(layer "F.Cu")
		(net "M_A_CPU1_SA_CB<4>")
	)
	(segment
		(start 75.081384 -267.220446)
		(end 76.448666 -267.220446)
		(width 0.1016)
		(layer "F.Cu")
		(net "M_A_CPU1_SA_CB<4>")
	)
	(segment
		(start 60.093606 -272.966688)
		(end 60.947046 -272.966688)
		(width 0.20066)
		(layer "F.Cu")
		(net "M_A_CPU1_SA_CB<4>")
	)
	(segment
		(start 84.542376 -261.522718)
		(end 85.435694 -261.522718)
		(width 0.088646)
		(layer "F.Cu")
		(net "M_A_CPU1_SA_CB<4>")
	)
	(segment
		(start 56.044338 -272.541746)
		(end 56.459374 -272.541746)
		(width 0.101854)
		(layer "F.Cu")
		(net "M_A_CPU1_SA_CB<4>")
	)
	(segment
		(start 58.643012 -272.541746)
		(end 58.971688 -272.541746)
		(width 0.101854)
		(layer "F.Cu")
		(net "M_A_CPU1_SA_CB<4>")
	)
	(segment
		(start 54.872382 -272.455132)
		(end 55.11292 -272.214594)
		(width 0.20066)
		(layer "F.Cu")
		(net "M_A_CPU1_SA_CB<4>")
	)
	(segment
		(start 83.861148 -261.728458)
		(end 84.336636 -261.728458)
		(width 0.088646)
		(layer "F.Cu")
		(net "M_A_CPU1_SA_CB<4>")
	)
	(segment
		(start 53.403246 -272.966688)
		(end 54.247034 -272.966688)
		(width 0.20066)
		(layer "F.Cu")
		(net "M_A_CPU1_SA_CB<4>")
	)
	(segment
		(start 63.281052 -273.039332)
		(end 63.281052 -272.775172)
		(width 0.20066)
		(layer "F.Cu")
		(net "M_A_CPU1_SA_CB<4>")
	)
	(segment
		(start 83.503516 -261.568692)
		(end 83.701382 -261.568692)
		(width 0.088646)
		(layer "F.Cu")
		(net "M_A_CPU1_SA_CB<4>")
	)
	(segment
		(start 84.4169 -263.11098)
		(end 84.150962 -263.221216)
		(width 0.088646)
		(layer "F.Cu")
		(net "M_A_CPU1_SA_CB<3>")
	)
	(segment
		(start 72.158606 -274.039584)
		(end 71.701914 -274.039584)
		(width 0.20066)
		(layer "F.Cu")
		(net "M_A_CPU1_SA_CB<3>")
	)
	(segment
		(start 68.086986 -276.816058)
		(end 67.713352 -276.442424)
		(width 0.20066)
		(layer "F.Cu")
		(net "M_A_CPU1_SA_CB<3>")
	)
	(segment
		(start 76.826364 -268.847062)
		(end 76.689966 -268.98346)
		(width 0.1016)
		(layer "F.Cu")
		(net "M_A_CPU1_SA_CB<3>")
	)
	(segment
		(start 84.68868 -262.973566)
		(end 84.42579 -263.106916)
		(width 0.088646)
		(layer "F.Cu")
		(net "M_A_CPU1_SA_CB<3>")
	)
	(segment
		(start 76.689966 -269.051532)
		(end 76.094844 -269.646654)
		(width 0.1016)
		(layer "F.Cu")
		(net "M_A_CPU1_SA_CB<3>")
	)
	(segment
		(start 62.881764 -276.28469)
		(end 63.289942 -276.28469)
		(width 0.20066)
		(layer "F.Cu")
		(net "M_A_CPU1_SA_CB<3>")
	)
	(segment
		(start 72.43318 -273.308318)
		(end 72.43318 -273.76501)
		(width 0.20066)
		(layer "F.Cu")
		(net "M_A_CPU1_SA_CB<3>")
	)
	(segment
		(start 62.682374 -276.679152)
		(end 62.682374 -276.48408)
		(width 0.20066)
		(layer "F.Cu")
		(net "M_A_CPU1_SA_CB<3>")
	)
	(segment
		(start 62.682374 -276.48408)
		(end 62.881764 -276.28469)
		(width 0.20066)
		(layer "F.Cu")
		(net "M_A_CPU1_SA_CB<3>")
	)
	(segment
		(start 69.420994 -276.051264)
		(end 68.6562 -276.816058)
		(width 0.20066)
		(layer "F.Cu")
		(net "M_A_CPU1_SA_CB<3>")
	)
	(segment
		(start 71.152766 -275.045424)
		(end 70.696074 -275.045424)
		(width 0.20066)
		(layer "F.Cu")
		(net "M_A_CPU1_SA_CB<3>")
	)
	(segment
		(start 86.691724 -262.881364)
		(end 86.625938 -262.862822)
		(width 0.088646)
		(layer "F.Cu")
		(net "M_A_CPU1_SA_CB<3>")
	)
	(segment
		(start 63.289942 -276.28469)
		(end 63.640716 -276.635464)
		(width 0.20066)
		(layer "F.Cu")
		(net "M_A_CPU1_SA_CB<3>")
	)
	(segment
		(start 70.696074 -275.045424)
		(end 70.4215 -275.319998)
		(width 0.20066)
		(layer "F.Cu")
		(net "M_A_CPU1_SA_CB<3>")
	)
	(segment
		(start 83.74888 -263.301226)
		(end 82.524346 -263.301226)
		(width 0.1016)
		(layer "F.Cu")
		(net "M_A_CPU1_SA_CB<3>")
	)
	(segment
		(start 68.6562 -276.816058)
		(end 68.086986 -276.816058)
		(width 0.20066)
		(layer "F.Cu")
		(net "M_A_CPU1_SA_CB<3>")
	)
	(segment
		(start 59.858402 -276.791674)
		(end 62.080394 -276.791674)
		(width 0.1016)
		(layer "F.Cu")
		(net "M_A_CPU1_SA_CB<3>")
	)
	(segment
		(start 87.71763 -262.7122)
		(end 87.570818 -262.726424)
		(width 0.088646)
		(layer "F.Cu")
		(net "M_A_CPU1_SA_CB<3>")
	)
	(segment
		(start 76.97851 -268.847062)
		(end 76.826364 -268.847062)
		(width 0.1016)
		(layer "F.Cu")
		(net "M_A_CPU1_SA_CB<3>")
	)
	(segment
		(start 70.4215 -275.319998)
		(end 70.4215 -275.77669)
		(width 0.20066)
		(layer "F.Cu")
		(net "M_A_CPU1_SA_CB<3>")
	)
	(segment
		(start 83.886548 -263.273794)
		(end 83.877404 -263.275572)
		(width 0.088646)
		(layer "F.Cu")
		(net "M_A_CPU1_SA_CB<3>")
	)
	(segment
		(start 71.42734 -274.314158)
		(end 71.42734 -274.77085)
		(width 0.20066)
		(layer "F.Cu")
		(net "M_A_CPU1_SA_CB<3>")
	)
	(segment
		(start 71.701914 -274.039584)
		(end 71.42734 -274.314158)
		(width 0.20066)
		(layer "F.Cu")
		(net "M_A_CPU1_SA_CB<3>")
	)
	(segment
		(start 63.640716 -276.635464)
		(end 63.924942 -276.635464)
		(width 0.20066)
		(layer "F.Cu")
		(net "M_A_CPU1_SA_CB<3>")
	)
	(segment
		(start 59.004708 -276.366732)
		(end 59.004962 -276.366478)
		(width 0.20066)
		(layer "F.Cu")
		(net "M_A_CPU1_SA_CB<3>")
	)
	(segment
		(start 57.503314 -276.366732)
		(end 59.004708 -276.366732)
		(width 0.20066)
		(layer "F.Cu")
		(net "M_A_CPU1_SA_CB<3>")
	)
	(segment
		(start 84.150962 -263.221216)
		(end 83.969606 -263.257284)
		(width 0.088646)
		(layer "F.Cu")
		(net "M_A_CPU1_SA_CB<3>")
	)
	(segment
		(start 70.4215 -275.77669)
		(end 70.146926 -276.051264)
		(width 0.20066)
		(layer "F.Cu")
		(net "M_A_CPU1_SA_CB<3>")
	)
	(segment
		(start 67.713352 -276.442424)
		(end 67.12077 -276.442424)
		(width 0.20066)
		(layer "F.Cu")
		(net "M_A_CPU1_SA_CB<3>")
	)
	(segment
		(start 63.924942 -276.635464)
		(end 64.193674 -276.366732)
		(width 0.20066)
		(layer "F.Cu")
		(net "M_A_CPU1_SA_CB<3>")
	)
	(segment
		(start 62.080394 -276.791674)
		(end 62.408308 -276.791674)
		(width 0.101854)
		(layer "F.Cu")
		(net "M_A_CPU1_SA_CB<3>")
	)
	(segment
		(start 70.146926 -276.051264)
		(end 69.420994 -276.051264)
		(width 0.20066)
		(layer "F.Cu")
		(net "M_A_CPU1_SA_CB<3>")
	)
	(segment
		(start 87.671402 -263.328404)
		(end 87.856568 -263.143238)
		(width 0.088646)
		(layer "F.Cu")
		(net "M_A_CPU1_SA_CB<3>")
	)
	(segment
		(start 59.004962 -276.366478)
		(end 59.430158 -276.791674)
		(width 0.20066)
		(layer "F.Cu")
		(net "M_A_CPU1_SA_CB<3>")
	)
	(segment
		(start 72.43318 -273.76501)
		(end 72.158606 -274.039584)
		(width 0.20066)
		(layer "F.Cu")
		(net "M_A_CPU1_SA_CB<3>")
	)
	(segment
		(start 82.524346 -263.301226)
		(end 76.97851 -268.847062)
		(width 0.1016)
		(layer "F.Cu")
		(net "M_A_CPU1_SA_CB<3>")
	)
	(segment
		(start 83.877404 -263.275572)
		(end 83.74888 -263.301226)
		(width 0.1016)
		(layer "F.Cu")
		(net "M_A_CPU1_SA_CB<3>")
	)
	(segment
		(start 87.315294 -263.150604)
		(end 87.493094 -263.328404)
		(width 0.088646)
		(layer "F.Cu")
		(net "M_A_CPU1_SA_CB<3>")
	)
	(segment
		(start 59.509152 -276.791674)
		(end 59.858402 -276.791674)
		(width 0.101854)
		(layer "F.Cu")
		(net "M_A_CPU1_SA_CB<3>")
	)
	(segment
		(start 64.193674 -276.366732)
		(end 65.047114 -276.366732)
		(width 0.20066)
		(layer "F.Cu")
		(net "M_A_CPU1_SA_CB<3>")
	)
	(segment
		(start 66.891662 -276.671532)
		(end 66.607436 -276.671532)
		(width 0.20066)
		(layer "F.Cu")
		(net "M_A_CPU1_SA_CB<3>")
	)
	(segment
		(start 87.493094 -263.328404)
		(end 87.671402 -263.328404)
		(width 0.088646)
		(layer "F.Cu")
		(net "M_A_CPU1_SA_CB<3>")
	)
	(segment
		(start 62.408308 -276.791674)
		(end 62.569852 -276.791674)
		(width 0.20066)
		(layer "F.Cu")
		(net "M_A_CPU1_SA_CB<3>")
	)
	(segment
		(start 67.12077 -276.442424)
		(end 66.891662 -276.671532)
		(width 0.20066)
		(layer "F.Cu")
		(net "M_A_CPU1_SA_CB<3>")
	)
	(segment
		(start 87.856568 -262.851138)
		(end 87.71763 -262.7122)
		(width 0.088646)
		(layer "F.Cu")
		(net "M_A_CPU1_SA_CB<3>")
	)
	(segment
		(start 62.569852 -276.791674)
		(end 62.682374 -276.679152)
		(width 0.20066)
		(layer "F.Cu")
		(net "M_A_CPU1_SA_CB<3>")
	)
	(segment
		(start 87.856568 -263.143238)
		(end 87.856568 -262.851138)
		(width 0.088646)
		(layer "F.Cu")
		(net "M_A_CPU1_SA_CB<3>")
	)
	(segment
		(start 76.689966 -268.98346)
		(end 76.689966 -269.051532)
		(width 0.1016)
		(layer "F.Cu")
		(net "M_A_CPU1_SA_CB<3>")
	)
	(segment
		(start 66.302636 -276.366732)
		(end 65.047114 -276.366732)
		(width 0.20066)
		(layer "F.Cu")
		(net "M_A_CPU1_SA_CB<3>")
	)
	(segment
		(start 71.42734 -274.77085)
		(end 71.152766 -275.045424)
		(width 0.20066)
		(layer "F.Cu")
		(net "M_A_CPU1_SA_CB<3>")
	)
	(segment
		(start 66.607436 -276.671532)
		(end 66.302636 -276.366732)
		(width 0.20066)
		(layer "F.Cu")
		(net "M_A_CPU1_SA_CB<3>")
	)
	(segment
		(start 59.430158 -276.791674)
		(end 59.509152 -276.791674)
		(width 0.20066)
		(layer "F.Cu")
		(net "M_A_CPU1_SA_CB<3>")
	)
	(segment
		(start 76.094844 -269.646654)
		(end 72.43318 -273.308318)
		(width 0.20066)
		(layer "F.Cu")
		(net "M_A_CPU1_SA_CB<3>")
	)
	(segment
		(start 83.969606 -263.257284)
		(end 83.886548 -263.273794)
		(width 0.088646)
		(layer "F.Cu")
		(net "M_A_CPU1_SA_CB<3>")
	)
	(arc
		(start 84.42579 -263.106916)
		(mid 84.421384 -263.109034)
		(end 84.4169 -263.11098)
		(width 0.088646)
		(layer "F.Cu")
		(net "M_A_CPU1_SA_CB<3>")
	)
	(arc
		(start 85.183472 -262.869426)
		(mid 85.000882 -262.922385)
		(end 84.81187 -262.942832)
		(width 0.088646)
		(layer "F.Cu")
		(net "M_A_CPU1_SA_CB<3>")
	)
	(arc
		(start 87.069168 -262.855964)
		(mid 86.882632 -262.901181)
		(end 86.691724 -262.881364)
		(width 0.088646)
		(layer "F.Cu")
		(net "M_A_CPU1_SA_CB<3>")
	)
	(arc
		(start 86.347046 -262.78967)
		(mid 86.125214 -262.801879)
		(end 85.903054 -262.80364)
		(width 0.088646)
		(layer "F.Cu")
		(net "M_A_CPU1_SA_CB<3>")
	)
	(arc
		(start 86.543388 -262.829802)
		(mid 86.448666 -262.796062)
		(end 86.348316 -262.78967)
		(width 0.088646)
		(layer "F.Cu")
		(net "M_A_CPU1_SA_CB<3>")
	)
	(arc
		(start 85.46465 -262.78967)
		(mid 85.361269 -262.796241)
		(end 85.26399 -262.831834)
		(width 0.088646)
		(layer "F.Cu")
		(net "M_A_CPU1_SA_CB<3>")
	)
	(arc
		(start 87.103458 -262.841486)
		(mid 87.086273 -262.84863)
		(end 87.069168 -262.855964)
		(width 0.088646)
		(layer "F.Cu")
		(net "M_A_CPU1_SA_CB<3>")
	)
	(arc
		(start 87.570818 -262.726424)
		(mid 87.432614 -262.745563)
		(end 87.296498 -262.776208)
		(width 0.088646)
		(layer "F.Cu")
		(net "M_A_CPU1_SA_CB<3>")
	)
	(arc
		(start 85.903054 -262.80364)
		(mid 85.683686 -262.801877)
		(end 85.46465 -262.78967)
		(width 0.088646)
		(layer "F.Cu")
		(net "M_A_CPU1_SA_CB<3>")
	)
	(arc
		(start 84.81187 -262.942832)
		(mid 84.748532 -262.951216)
		(end 84.68868 -262.973566)
		(width 0.088646)
		(layer "F.Cu")
		(net "M_A_CPU1_SA_CB<3>")
	)
	(arc
		(start 87.296498 -262.776208)
		(mid 87.195458 -262.795479)
		(end 87.103458 -262.841486)
		(width 0.088646)
		(layer "F.Cu")
		(net "M_A_CPU1_SA_CB<3>")
	)
	(arc
		(start 85.26399 -262.831834)
		(mid 85.224315 -262.85188)
		(end 85.183472 -262.869426)
		(width 0.088646)
		(layer "F.Cu")
		(net "M_A_CPU1_SA_CB<3>")
	)
	(arc
		(start 86.348316 -262.78967)
		(mid 86.347681 -262.789669)
		(end 86.347046 -262.78967)
		(width 0.088646)
		(layer "F.Cu")
		(net "M_A_CPU1_SA_CB<3>")
	)
	(arc
		(start 86.625938 -262.862822)
		(mid 86.583813 -262.848438)
		(end 86.543388 -262.829802)
		(width 0.088646)
		(layer "F.Cu")
		(net "M_A_CPU1_SA_CB<3>")
	)
	(segment
		(start 86.180676 -263.728962)
		(end 86.180676 -263.46785)
		(width 0.088646)
		(layer "F.Cu")
		(net "M_A_CPU1_SA_CB<2>")
	)
	(segment
		(start 72.81672 -275.249894)
		(end 72.61606 -275.450554)
		(width 0.20066)
		(layer "F.Cu")
		(net "M_A_CPU1_SA_CB<2>")
	)
	(segment
		(start 70.469252 -278.172926)
		(end 67.269614 -278.172926)
		(width 0.20066)
		(layer "F.Cu")
		(net "M_A_CPU1_SA_CB<2>")
	)
	(segment
		(start 76.185014 -271.370552)
		(end 76.094844 -271.460722)
		(width 0.1016)
		(layer "F.Cu")
		(net "M_A_CPU1_SA_CB<2>")
	)
	(segment
		(start 85.581744 -263.550908)
		(end 85.426296 -263.550908)
		(width 0.088646)
		(layer "F.Cu")
		(net "M_A_CPU1_SA_CB<2>")
	)
	(segment
		(start 86.180676 -263.46785)
		(end 85.988652 -263.275826)
		(width 0.088646)
		(layer "F.Cu")
		(net "M_A_CPU1_SA_CB<2>")
	)
	(segment
		(start 59.22899 -277.641558)
		(end 59.712606 -277.641558)
		(width 0.20066)
		(layer "F.Cu")
		(net "M_A_CPU1_SA_CB<2>")
	)
	(segment
		(start 86.845648 -263.858756)
		(end 86.791546 -263.804654)
		(width 0.088646)
		(layer "F.Cu")
		(net "M_A_CPU1_SA_CB<2>")
	)
	(segment
		(start 72.61606 -275.450554)
		(end 72.61606 -276.026118)
		(width 0.20066)
		(layer "F.Cu")
		(net "M_A_CPU1_SA_CB<2>")
	)
	(segment
		(start 83.248754 -263.92378)
		(end 83.068668 -263.92378)
		(width 0.088646)
		(layer "F.Cu")
		(net "M_A_CPU1_SA_CB<2>")
	)
	(segment
		(start 73.392284 -275.249894)
		(end 72.81672 -275.249894)
		(width 0.20066)
		(layer "F.Cu")
		(net "M_A_CPU1_SA_CB<2>")
	)
	(segment
		(start 73.495408 -275.14677)
		(end 73.392284 -275.249894)
		(width 0.20066)
		(layer "F.Cu")
		(net "M_A_CPU1_SA_CB<2>")
	)
	(segment
		(start 71.81088 -276.255734)
		(end 71.61022 -276.456394)
		(width 0.20066)
		(layer "F.Cu")
		(net "M_A_CPU1_SA_CB<2>")
	)
	(segment
		(start 59.887612 -277.641558)
		(end 62.122812 -277.641558)
		(width 0.1016)
		(layer "F.Cu")
		(net "M_A_CPU1_SA_CB<2>")
	)
	(segment
		(start 86.791546 -263.804654)
		(end 86.256368 -263.804654)
		(width 0.088646)
		(layer "F.Cu")
		(net "M_A_CPU1_SA_CB<2>")
	)
	(segment
		(start 85.856826 -263.275826)
		(end 85.581744 -263.550908)
		(width 0.088646)
		(layer "F.Cu")
		(net "M_A_CPU1_SA_CB<2>")
	)
	(segment
		(start 83.492594 -263.845294)
		(end 83.32724 -263.845294)
		(width 0.088646)
		(layer "F.Cu")
		(net "M_A_CPU1_SA_CB<2>")
	)
	(segment
		(start 86.256368 -263.804654)
		(end 86.180676 -263.728962)
		(width 0.088646)
		(layer "F.Cu")
		(net "M_A_CPU1_SA_CB<2>")
	)
	(segment
		(start 62.51702 -278.02205)
		(end 62.666118 -278.171148)
		(width 0.20066)
		(layer "F.Cu")
		(net "M_A_CPU1_SA_CB<2>")
	)
	(segment
		(start 82.997294 -263.852406)
		(end 82.836004 -263.852406)
		(width 0.088646)
		(layer "F.Cu")
		(net "M_A_CPU1_SA_CB<2>")
	)
	(segment
		(start 63.080392 -278.066754)
		(end 65.047114 -278.066754)
		(width 0.20066)
		(layer "F.Cu")
		(net "M_A_CPU1_SA_CB<2>")
	)
	(segment
		(start 70.60438 -278.037798)
		(end 70.469252 -278.172926)
		(width 0.20066)
		(layer "F.Cu")
		(net "M_A_CPU1_SA_CB<2>")
	)
	(segment
		(start 57.503314 -278.066754)
		(end 59.00039 -278.066754)
		(width 0.20066)
		(layer "F.Cu")
		(net "M_A_CPU1_SA_CB<2>")
	)
	(segment
		(start 62.51702 -277.72614)
		(end 62.51702 -278.02205)
		(width 0.20066)
		(layer "F.Cu")
		(net "M_A_CPU1_SA_CB<2>")
	)
	(segment
		(start 71.61022 -277.031958)
		(end 71.380604 -277.261574)
		(width 0.20066)
		(layer "F.Cu")
		(net "M_A_CPU1_SA_CB<2>")
	)
	(segment
		(start 82.62747 -264.06094)
		(end 76.797916 -269.890494)
		(width 0.1016)
		(layer "F.Cu")
		(net "M_A_CPU1_SA_CB<2>")
	)
	(segment
		(start 73.601072 -274.322286)
		(end 73.719182 -274.607274)
		(width 0.20066)
		(layer "F.Cu")
		(net "M_A_CPU1_SA_CB<2>")
	)
	(segment
		(start 59.712606 -277.641558)
		(end 59.887612 -277.641558)
		(width 0.101854)
		(layer "F.Cu")
		(net "M_A_CPU1_SA_CB<2>")
	)
	(segment
		(start 73.719182 -274.607274)
		(end 73.495408 -275.14677)
		(width 0.20066)
		(layer "F.Cu")
		(net "M_A_CPU1_SA_CB<2>")
	)
	(segment
		(start 84.57946 -263.470898)
		(end 84.570062 -263.470898)
		(width 0.088646)
		(layer "F.Cu")
		(net "M_A_CPU1_SA_CB<2>")
	)
	(segment
		(start 62.666118 -278.171148)
		(end 62.97549 -278.171148)
		(width 0.20066)
		(layer "F.Cu")
		(net "M_A_CPU1_SA_CB<2>")
	)
	(segment
		(start 62.97549 -278.171148)
		(end 63.080138 -278.0665)
		(width 0.20066)
		(layer "F.Cu")
		(net "M_A_CPU1_SA_CB<2>")
	)
	(segment
		(start 59.102752 -277.964392)
		(end 59.102752 -277.767796)
		(width 0.20066)
		(layer "F.Cu")
		(net "M_A_CPU1_SA_CB<2>")
	)
	(segment
		(start 82.836004 -263.852406)
		(end 82.62747 -264.06094)
		(width 0.088646)
		(layer "F.Cu")
		(net "M_A_CPU1_SA_CB<2>")
	)
	(segment
		(start 84.956396 -263.39673)
		(end 84.955634 -263.396476)
		(width 0.088646)
		(layer "F.Cu")
		(net "M_A_CPU1_SA_CB<2>")
	)
	(segment
		(start 67.269614 -278.172926)
		(end 67.26936 -278.172672)
		(width 0.20066)
		(layer "F.Cu")
		(net "M_A_CPU1_SA_CB<2>")
	)
	(segment
		(start 67.26936 -278.172672)
		(end 66.695066 -278.172672)
		(width 0.20066)
		(layer "F.Cu")
		(net "M_A_CPU1_SA_CB<2>")
	)
	(segment
		(start 74.079608 -273.736816)
		(end 73.79462 -273.854926)
		(width 0.20066)
		(layer "F.Cu")
		(net "M_A_CPU1_SA_CB<2>")
	)
	(segment
		(start 85.988652 -263.275826)
		(end 85.856826 -263.275826)
		(width 0.088646)
		(layer "F.Cu")
		(net "M_A_CPU1_SA_CB<2>")
	)
	(segment
		(start 62.168786 -277.641558)
		(end 62.432438 -277.641558)
		(width 0.20066)
		(layer "F.Cu")
		(net "M_A_CPU1_SA_CB<2>")
	)
	(segment
		(start 72.61606 -276.026118)
		(end 72.386444 -276.255734)
		(width 0.20066)
		(layer "F.Cu")
		(net "M_A_CPU1_SA_CB<2>")
	)
	(segment
		(start 59.102752 -277.767796)
		(end 59.22899 -277.641558)
		(width 0.20066)
		(layer "F.Cu")
		(net "M_A_CPU1_SA_CB<2>")
	)
	(segment
		(start 62.122812 -277.641558)
		(end 62.168786 -277.641558)
		(width 0.101854)
		(layer "F.Cu")
		(net "M_A_CPU1_SA_CB<2>")
	)
	(segment
		(start 84.195666 -263.845294)
		(end 84.012532 -263.845294)
		(width 0.088646)
		(layer "F.Cu")
		(net "M_A_CPU1_SA_CB<2>")
	)
	(segment
		(start 84.012532 -263.845294)
		(end 83.87334 -263.984486)
		(width 0.088646)
		(layer "F.Cu")
		(net "M_A_CPU1_SA_CB<2>")
	)
	(segment
		(start 83.32724 -263.845294)
		(end 83.248754 -263.92378)
		(width 0.088646)
		(layer "F.Cu")
		(net "M_A_CPU1_SA_CB<2>")
	)
	(segment
		(start 86.845648 -263.96442)
		(end 86.845648 -263.858756)
		(width 0.088646)
		(layer "F.Cu")
		(net "M_A_CPU1_SA_CB<2>")
	)
	(segment
		(start 62.432438 -277.641558)
		(end 62.51702 -277.72614)
		(width 0.20066)
		(layer "F.Cu")
		(net "M_A_CPU1_SA_CB<2>")
	)
	(segment
		(start 66.589148 -278.066754)
		(end 65.047114 -278.066754)
		(width 0.20066)
		(layer "F.Cu")
		(net "M_A_CPU1_SA_CB<2>")
	)
	(segment
		(start 84.79917 -263.404096)
		(end 84.57946 -263.470898)
		(width 0.088646)
		(layer "F.Cu")
		(net "M_A_CPU1_SA_CB<2>")
	)
	(segment
		(start 84.570062 -263.470898)
		(end 84.195666 -263.845294)
		(width 0.088646)
		(layer "F.Cu")
		(net "M_A_CPU1_SA_CB<2>")
	)
	(segment
		(start 73.79462 -273.854926)
		(end 73.601072 -274.322286)
		(width 0.20066)
		(layer "F.Cu")
		(net "M_A_CPU1_SA_CB<2>")
	)
	(segment
		(start 70.60438 -277.462234)
		(end 70.60438 -278.037798)
		(width 0.20066)
		(layer "F.Cu")
		(net "M_A_CPU1_SA_CB<2>")
	)
	(segment
		(start 66.695066 -278.172672)
		(end 66.589148 -278.066754)
		(width 0.20066)
		(layer "F.Cu")
		(net "M_A_CPU1_SA_CB<2>")
	)
	(segment
		(start 71.380604 -277.261574)
		(end 70.80504 -277.261574)
		(width 0.20066)
		(layer "F.Cu")
		(net "M_A_CPU1_SA_CB<2>")
	)
	(segment
		(start 70.80504 -277.261574)
		(end 70.60438 -277.462234)
		(width 0.20066)
		(layer "F.Cu")
		(net "M_A_CPU1_SA_CB<2>")
	)
	(segment
		(start 63.080138 -278.0665)
		(end 63.080392 -278.066754)
		(width 0.20066)
		(layer "F.Cu")
		(net "M_A_CPU1_SA_CB<2>")
	)
	(segment
		(start 84.937854 -263.39673)
		(end 84.79917 -263.404096)
		(width 0.088646)
		(layer "F.Cu")
		(net "M_A_CPU1_SA_CB<2>")
	)
	(segment
		(start 72.386444 -276.255734)
		(end 71.81088 -276.255734)
		(width 0.20066)
		(layer "F.Cu")
		(net "M_A_CPU1_SA_CB<2>")
	)
	(segment
		(start 83.87334 -263.984486)
		(end 83.631786 -263.984486)
		(width 0.088646)
		(layer "F.Cu")
		(net "M_A_CPU1_SA_CB<2>")
	)
	(segment
		(start 71.61022 -276.456394)
		(end 71.61022 -277.031958)
		(width 0.20066)
		(layer "F.Cu")
		(net "M_A_CPU1_SA_CB<2>")
	)
	(segment
		(start 84.978494 -263.39673)
		(end 84.956396 -263.39673)
		(width 0.088646)
		(layer "F.Cu")
		(net "M_A_CPU1_SA_CB<2>")
	)
	(segment
		(start 83.631786 -263.984486)
		(end 83.492594 -263.845294)
		(width 0.088646)
		(layer "F.Cu")
		(net "M_A_CPU1_SA_CB<2>")
	)
	(segment
		(start 59.00039 -278.066754)
		(end 59.102752 -277.964392)
		(width 0.20066)
		(layer "F.Cu")
		(net "M_A_CPU1_SA_CB<2>")
	)
	(segment
		(start 76.094844 -271.460722)
		(end 74.263758 -273.291808)
		(width 0.20066)
		(layer "F.Cu")
		(net "M_A_CPU1_SA_CB<2>")
	)
	(segment
		(start 74.263758 -273.291808)
		(end 74.079608 -273.736816)
		(width 0.20066)
		(layer "F.Cu")
		(net "M_A_CPU1_SA_CB<2>")
	)
	(segment
		(start 83.068668 -263.92378)
		(end 82.997294 -263.852406)
		(width 0.088646)
		(layer "F.Cu")
		(net "M_A_CPU1_SA_CB<2>")
	)
	(segment
		(start 76.797916 -269.890494)
		(end 76.185014 -271.370552)
		(width 0.1016)
		(layer "F.Cu")
		(net "M_A_CPU1_SA_CB<2>")
	)
	(arc
		(start 85.426296 -263.550908)
		(mid 85.334279 -263.518639)
		(end 85.246972 -263.475216)
		(width 0.088646)
		(layer "F.Cu")
		(net "M_A_CPU1_SA_CB<2>")
	)
	(arc
		(start 85.08365 -263.410954)
		(mid 85.031393 -263.401467)
		(end 84.978494 -263.39673)
		(width 0.088646)
		(layer "F.Cu")
		(net "M_A_CPU1_SA_CB<2>")
	)
	(arc
		(start 85.246972 -263.475216)
		(mid 85.199847 -263.450692)
		(end 85.150706 -263.430512)
		(width 0.088646)
		(layer "F.Cu")
		(net "M_A_CPU1_SA_CB<2>")
	)
	(arc
		(start 85.150706 -263.430512)
		(mid 85.117476 -263.419711)
		(end 85.08365 -263.410954)
		(width 0.088646)
		(layer "F.Cu")
		(net "M_A_CPU1_SA_CB<2>")
	)
	(arc
		(start 84.955634 -263.396476)
		(mid 84.946743 -263.396544)
		(end 84.937854 -263.39673)
		(width 0.088646)
		(layer "F.Cu")
		(net "M_A_CPU1_SA_CB<2>")
	)
	(segment
		(start 66.428112 -277.641558)
		(end 66.592704 -277.476966)
		(width 0.20066)
		(layer "F.Cu")
		(net "M_A_CPU1_SA_CB<1>")
	)
	(segment
		(start 82.648298 -263.608566)
		(end 83.916774 -263.608566)
		(width 0.088646)
		(layer "F.Cu")
		(net "M_A_CPU1_SA_CB<1>")
	)
	(segment
		(start 60.947046 -277.216616)
		(end 62.827154 -277.216616)
		(width 0.20066)
		(layer "F.Cu")
		(net "M_A_CPU1_SA_CB<1>")
	)
	(segment
		(start 58.838846 -276.791674)
		(end 59.263788 -277.216616)
		(width 0.20066)
		(layer "F.Cu")
		(net "M_A_CPU1_SA_CB<1>")
	)
	(segment
		(start 84.760308 -263.150604)
		(end 85.435694 -263.150604)
		(width 0.088646)
		(layer "F.Cu")
		(net "M_A_CPU1_SA_CB<1>")
	)
	(segment
		(start 56.915558 -276.791674)
		(end 58.668412 -276.791674)
		(width 0.1016)
		(layer "F.Cu")
		(net "M_A_CPU1_SA_CB<1>")
	)
	(segment
		(start 66.204592 -277.641558)
		(end 66.25971 -277.641558)
		(width 0.101854)
		(layer "F.Cu")
		(net "M_A_CPU1_SA_CB<1>")
	)
	(segment
		(start 55.9308 -276.76475)
		(end 56.37911 -276.76475)
		(width 0.20066)
		(layer "F.Cu")
		(net "M_A_CPU1_SA_CB<1>")
	)
	(segment
		(start 72.973184 -274.145756)
		(end 73.306178 -273.3421)
		(width 0.20066)
		(layer "F.Cu")
		(net "M_A_CPU1_SA_CB<1>")
	)
	(segment
		(start 66.25971 -277.641558)
		(end 66.428112 -277.641558)
		(width 0.20066)
		(layer "F.Cu")
		(net "M_A_CPU1_SA_CB<1>")
	)
	(segment
		(start 59.263788 -277.216616)
		(end 60.947046 -277.216616)
		(width 0.20066)
		(layer "F.Cu")
		(net "M_A_CPU1_SA_CB<1>")
	)
	(segment
		(start 82.586576 -263.670288)
		(end 82.648298 -263.608566)
		(width 0.088646)
		(layer "F.Cu")
		(net "M_A_CPU1_SA_CB<1>")
	)
	(segment
		(start 76.258166 -270.390112)
		(end 76.258166 -270.127476)
		(width 0.1016)
		(layer "F.Cu")
		(net "M_A_CPU1_SA_CB<1>")
	)
	(segment
		(start 83.916774 -263.608566)
		(end 84.760308 -263.150604)
		(width 0.088646)
		(layer "F.Cu")
		(net "M_A_CPU1_SA_CB<1>")
	)
	(segment
		(start 76.419456 -269.966186)
		(end 76.419456 -269.837408)
		(width 0.1016)
		(layer "F.Cu")
		(net "M_A_CPU1_SA_CB<1>")
	)
	(segment
		(start 58.758328 -276.791674)
		(end 58.838846 -276.791674)
		(width 0.20066)
		(layer "F.Cu")
		(net "M_A_CPU1_SA_CB<1>")
	)
	(segment
		(start 54.383432 -277.335742)
		(end 54.872128 -277.335742)
		(width 0.20066)
		(layer "F.Cu")
		(net "M_A_CPU1_SA_CB<1>")
	)
	(segment
		(start 58.668412 -276.791674)
		(end 58.758328 -276.791674)
		(width 0.101854)
		(layer "F.Cu")
		(net "M_A_CPU1_SA_CB<1>")
	)
	(segment
		(start 66.592704 -277.476966)
		(end 69.641974 -277.476966)
		(width 0.20066)
		(layer "F.Cu")
		(net "M_A_CPU1_SA_CB<1>")
	)
	(segment
		(start 54.872128 -277.335742)
		(end 55.128414 -277.079456)
		(width 0.20066)
		(layer "F.Cu")
		(net "M_A_CPU1_SA_CB<1>")
	)
	(segment
		(start 56.406034 -276.791674)
		(end 56.915558 -276.791674)
		(width 0.101854)
		(layer "F.Cu")
		(net "M_A_CPU1_SA_CB<1>")
	)
	(segment
		(start 69.641974 -277.476966)
		(end 72.973184 -274.145756)
		(width 0.20066)
		(layer "F.Cu")
		(net "M_A_CPU1_SA_CB<1>")
	)
	(segment
		(start 55.632604 -276.466554)
		(end 55.9308 -276.76475)
		(width 0.20066)
		(layer "F.Cu")
		(net "M_A_CPU1_SA_CB<1>")
	)
	(segment
		(start 76.094844 -270.553434)
		(end 76.258166 -270.390112)
		(width 0.1016)
		(layer "F.Cu")
		(net "M_A_CPU1_SA_CB<1>")
	)
	(segment
		(start 63.252096 -277.641558)
		(end 63.80353 -277.641558)
		(width 0.20066)
		(layer "F.Cu")
		(net "M_A_CPU1_SA_CB<1>")
	)
	(segment
		(start 56.37911 -276.76475)
		(end 56.406034 -276.791674)
		(width 0.101854)
		(layer "F.Cu")
		(net "M_A_CPU1_SA_CB<1>")
	)
	(segment
		(start 55.128414 -276.679152)
		(end 55.341012 -276.466554)
		(width 0.20066)
		(layer "F.Cu")
		(net "M_A_CPU1_SA_CB<1>")
	)
	(segment
		(start 55.128414 -277.079456)
		(end 55.128414 -276.679152)
		(width 0.20066)
		(layer "F.Cu")
		(net "M_A_CPU1_SA_CB<1>")
	)
	(segment
		(start 54.264306 -277.216616)
		(end 54.383432 -277.335742)
		(width 0.20066)
		(layer "F.Cu")
		(net "M_A_CPU1_SA_CB<1>")
	)
	(segment
		(start 64.185292 -277.641558)
		(end 66.204592 -277.641558)
		(width 0.1016)
		(layer "F.Cu")
		(net "M_A_CPU1_SA_CB<1>")
	)
	(segment
		(start 63.80353 -277.641558)
		(end 64.185292 -277.641558)
		(width 0.101854)
		(layer "F.Cu")
		(net "M_A_CPU1_SA_CB<1>")
	)
	(segment
		(start 73.306178 -273.3421)
		(end 76.094844 -270.553434)
		(width 0.20066)
		(layer "F.Cu")
		(net "M_A_CPU1_SA_CB<1>")
	)
	(segment
		(start 53.403246 -277.216616)
		(end 54.264306 -277.216616)
		(width 0.20066)
		(layer "F.Cu")
		(net "M_A_CPU1_SA_CB<1>")
	)
	(segment
		(start 62.827154 -277.216616)
		(end 63.252096 -277.641558)
		(width 0.20066)
		(layer "F.Cu")
		(net "M_A_CPU1_SA_CB<1>")
	)
	(segment
		(start 55.341012 -276.466554)
		(end 55.632604 -276.466554)
		(width 0.20066)
		(layer "F.Cu")
		(net "M_A_CPU1_SA_CB<1>")
	)
	(segment
		(start 76.419456 -269.837408)
		(end 82.586576 -263.670288)
		(width 0.1016)
		(layer "F.Cu")
		(net "M_A_CPU1_SA_CB<1>")
	)
	(segment
		(start 76.258166 -270.127476)
		(end 76.419456 -269.966186)
		(width 0.1016)
		(layer "F.Cu")
		(net "M_A_CPU1_SA_CB<1>")
	)
	(segment
		(start 56.281828 -278.491696)
		(end 56.37911 -278.491696)
		(width 0.101854)
		(layer "F.Cu")
		(net "M_A_CPU1_SA_CB<0>")
	)
	(segment
		(start 54.252114 -278.916638)
		(end 54.35981 -279.024334)
		(width 0.20066)
		(layer "F.Cu")
		(net "M_A_CPU1_SA_CB<0>")
	)
	(segment
		(start 74.048874 -275.509482)
		(end 70.737476 -278.82088)
		(width 0.20066)
		(layer "F.Cu")
		(net "M_A_CPU1_SA_CB<0>")
	)
	(segment
		(start 84.114386 -264.205466)
		(end 82.914236 -264.205466)
		(width 0.088646)
		(layer "F.Cu")
		(net "M_A_CPU1_SA_CB<0>")
	)
	(segment
		(start 55.323994 -278.319738)
		(end 55.752492 -278.319738)
		(width 0.20066)
		(layer "F.Cu")
		(net "M_A_CPU1_SA_CB<0>")
	)
	(segment
		(start 74.821288 -273.645122)
		(end 74.048874 -275.509482)
		(width 0.20066)
		(layer "F.Cu")
		(net "M_A_CPU1_SA_CB<0>")
	)
	(segment
		(start 66.745612 -278.82088)
		(end 66.3956 -278.470868)
		(width 0.20066)
		(layer "F.Cu")
		(net "M_A_CPU1_SA_CB<0>")
	)
	(segment
		(start 63.26378 -278.470868)
		(end 63.137034 -278.597614)
		(width 0.20066)
		(layer "F.Cu")
		(net "M_A_CPU1_SA_CB<0>")
	)
	(segment
		(start 54.35981 -279.024334)
		(end 54.863238 -279.024334)
		(width 0.20066)
		(layer "F.Cu")
		(net "M_A_CPU1_SA_CB<0>")
	)
	(segment
		(start 65.909444 -278.491696)
		(end 64.216788 -278.491696)
		(width 0.1016)
		(layer "F.Cu")
		(net "M_A_CPU1_SA_CB<0>")
	)
	(segment
		(start 59.097418 -278.491696)
		(end 59.52236 -278.916638)
		(width 0.20066)
		(layer "F.Cu")
		(net "M_A_CPU1_SA_CB<0>")
	)
	(segment
		(start 61.749178 -278.916638)
		(end 60.947046 -278.916638)
		(width 0.20066)
		(layer "F.Cu")
		(net "M_A_CPU1_SA_CB<0>")
	)
	(segment
		(start 82.680302 -264.4394)
		(end 77.074776 -270.044926)
		(width 0.1016)
		(layer "F.Cu")
		(net "M_A_CPU1_SA_CB<0>")
	)
	(segment
		(start 59.52236 -278.916638)
		(end 60.947046 -278.916638)
		(width 0.20066)
		(layer "F.Cu")
		(net "M_A_CPU1_SA_CB<0>")
	)
	(segment
		(start 64.216788 -278.491696)
		(end 63.824104 -278.491696)
		(width 0.101854)
		(layer "F.Cu")
		(net "M_A_CPU1_SA_CB<0>")
	)
	(segment
		(start 55.031386 -278.612346)
		(end 55.323994 -278.319738)
		(width 0.20066)
		(layer "F.Cu")
		(net "M_A_CPU1_SA_CB<0>")
	)
	(segment
		(start 53.403246 -278.916638)
		(end 54.252114 -278.916638)
		(width 0.20066)
		(layer "F.Cu")
		(net "M_A_CPU1_SA_CB<0>")
	)
	(segment
		(start 70.737476 -278.82088)
		(end 66.745612 -278.82088)
		(width 0.20066)
		(layer "F.Cu")
		(net "M_A_CPU1_SA_CB<0>")
	)
	(segment
		(start 55.031386 -278.856186)
		(end 55.031386 -278.612346)
		(width 0.20066)
		(layer "F.Cu")
		(net "M_A_CPU1_SA_CB<0>")
	)
	(segment
		(start 58.668412 -278.491696)
		(end 58.742072 -278.491696)
		(width 0.101854)
		(layer "F.Cu")
		(net "M_A_CPU1_SA_CB<0>")
	)
	(segment
		(start 66.310764 -278.470868)
		(end 66.289936 -278.491696)
		(width 0.101854)
		(layer "F.Cu")
		(net "M_A_CPU1_SA_CB<0>")
	)
	(segment
		(start 82.914236 -264.205466)
		(end 82.680302 -264.4394)
		(width 0.088646)
		(layer "F.Cu")
		(net "M_A_CPU1_SA_CB<0>")
	)
	(segment
		(start 77.074776 -270.044926)
		(end 76.12253 -272.34388)
		(width 0.1016)
		(layer "F.Cu")
		(net "M_A_CPU1_SA_CB<0>")
	)
	(segment
		(start 63.824104 -278.491696)
		(end 63.803276 -278.470868)
		(width 0.101854)
		(layer "F.Cu")
		(net "M_A_CPU1_SA_CB<0>")
	)
	(segment
		(start 75.610212 -272.856198)
		(end 74.821288 -273.645122)
		(width 0.20066)
		(layer "F.Cu")
		(net "M_A_CPU1_SA_CB<0>")
	)
	(segment
		(start 55.92445 -278.491696)
		(end 56.281828 -278.491696)
		(width 0.20066)
		(layer "F.Cu")
		(net "M_A_CPU1_SA_CB<0>")
	)
	(segment
		(start 85.320124 -263.737852)
		(end 85.148674 -263.638792)
		(width 0.088646)
		(layer "F.Cu")
		(net "M_A_CPU1_SA_CB<0>")
	)
	(segment
		(start 63.137034 -278.597614)
		(end 61.831474 -278.882602)
		(width 0.20066)
		(layer "F.Cu")
		(net "M_A_CPU1_SA_CB<0>")
	)
	(segment
		(start 54.863238 -279.024334)
		(end 55.031386 -278.856186)
		(width 0.20066)
		(layer "F.Cu")
		(net "M_A_CPU1_SA_CB<0>")
	)
	(segment
		(start 76.12253 -272.34388)
		(end 75.610212 -272.856198)
		(width 0.1016)
		(layer "F.Cu")
		(net "M_A_CPU1_SA_CB<0>")
	)
	(segment
		(start 66.3956 -278.470868)
		(end 66.310764 -278.470868)
		(width 0.20066)
		(layer "F.Cu")
		(net "M_A_CPU1_SA_CB<0>")
	)
	(segment
		(start 84.605368 -263.714484)
		(end 84.114386 -264.205466)
		(width 0.088646)
		(layer "F.Cu")
		(net "M_A_CPU1_SA_CB<0>")
	)
	(segment
		(start 63.803276 -278.470868)
		(end 63.26378 -278.470868)
		(width 0.20066)
		(layer "F.Cu")
		(net "M_A_CPU1_SA_CB<0>")
	)
	(segment
		(start 56.37911 -278.491696)
		(end 58.668412 -278.491696)
		(width 0.1016)
		(layer "F.Cu")
		(net "M_A_CPU1_SA_CB<0>")
	)
	(segment
		(start 58.742072 -278.491696)
		(end 59.097418 -278.491696)
		(width 0.20066)
		(layer "F.Cu")
		(net "M_A_CPU1_SA_CB<0>")
	)
	(segment
		(start 66.289936 -278.491696)
		(end 65.909444 -278.491696)
		(width 0.101854)
		(layer "F.Cu")
		(net "M_A_CPU1_SA_CB<0>")
	)
	(segment
		(start 84.767928 -263.627108)
		(end 84.605368 -263.714484)
		(width 0.088646)
		(layer "F.Cu")
		(net "M_A_CPU1_SA_CB<0>")
	)
	(segment
		(start 61.831474 -278.882602)
		(end 61.749178 -278.916638)
		(width 0.20066)
		(layer "F.Cu")
		(net "M_A_CPU1_SA_CB<0>")
	)
	(segment
		(start 85.905594 -263.96442)
		(end 85.320124 -263.737852)
		(width 0.088646)
		(layer "F.Cu")
		(net "M_A_CPU1_SA_CB<0>")
	)
	(segment
		(start 55.752492 -278.319738)
		(end 55.92445 -278.491696)
		(width 0.20066)
		(layer "F.Cu")
		(net "M_A_CPU1_SA_CB<0>")
	)
	(arc
		(start 85.148674 -263.638792)
		(mid 85.05582 -263.600215)
		(end 84.956142 -263.586976)
		(width 0.088646)
		(layer "F.Cu")
		(net "M_A_CPU1_SA_CB<0>")
	)
	(arc
		(start 84.956142 -263.586976)
		(mid 84.859904 -263.597059)
		(end 84.767928 -263.627108)
		(width 0.088646)
		(layer "F.Cu")
		(net "M_A_CPU1_SA_CB<0>")
	)
	(segment
		(start 58.643012 -261.49173)
		(end 58.704226 -261.49173)
		(width 0.101854)
		(layer "F.Cu")
		(net "M_A_CPU1_SA_CA<6>")
	)
	(segment
		(start 83.38947 -255.227074)
		(end 81.995518 -256.621026)
		(width 0.1016)
		(layer "F.Cu")
		(net "M_A_CPU1_SA_CA<6>")
	)
	(segment
		(start 85.905594 -254.197612)
		(end 85.399626 -253.954026)
		(width 0.088646)
		(layer "F.Cu")
		(net "M_A_CPU1_SA_CA<6>")
	)
	(segment
		(start 53.403246 -261.066788)
		(end 54.643528 -261.066788)
		(width 0.20066)
		(layer "F.Cu")
		(net "M_A_CPU1_SA_CA<6>")
	)
	(segment
		(start 66.19494 -261.49173)
		(end 64.001396 -261.49173)
		(width 0.1016)
		(layer "F.Cu")
		(net "M_A_CPU1_SA_CA<6>")
	)
	(segment
		(start 56.37911 -261.508494)
		(end 56.416448 -261.508494)
		(width 0.101854)
		(layer "F.Cu")
		(net "M_A_CPU1_SA_CA<6>")
	)
	(segment
		(start 63.330836 -261.066788)
		(end 60.947046 -261.066788)
		(width 0.20066)
		(layer "F.Cu")
		(net "M_A_CPU1_SA_CA<6>")
	)
	(segment
		(start 55.950612 -261.64413)
		(end 56.086248 -261.508494)
		(width 0.20066)
		(layer "F.Cu")
		(net "M_A_CPU1_SA_CA<6>")
	)
	(segment
		(start 67.328288 -260.76402)
		(end 66.969132 -260.912864)
		(width 0.20066)
		(layer "F.Cu")
		(net "M_A_CPU1_SA_CA<6>")
	)
	(segment
		(start 63.977012 -261.502906)
		(end 63.766954 -261.502906)
		(width 0.20066)
		(layer "F.Cu")
		(net "M_A_CPU1_SA_CA<6>")
	)
	(segment
		(start 73.89495 -256.985262)
		(end 69.135752 -258.956556)
		(width 0.20066)
		(layer "F.Cu")
		(net "M_A_CPU1_SA_CA<6>")
	)
	(segment
		(start 55.950612 -261.865872)
		(end 55.950612 -261.64413)
		(width 0.20066)
		(layer "F.Cu")
		(net "M_A_CPU1_SA_CA<6>")
	)
	(segment
		(start 56.086248 -261.508494)
		(end 56.37911 -261.508494)
		(width 0.20066)
		(layer "F.Cu")
		(net "M_A_CPU1_SA_CA<6>")
	)
	(segment
		(start 74.63028 -256.656078)
		(end 73.969372 -256.92989)
		(width 0.1016)
		(layer "F.Cu")
		(net "M_A_CPU1_SA_CA<6>")
	)
	(segment
		(start 73.895204 -256.985262)
		(end 73.89495 -256.985262)
		(width 0.101854)
		(layer "F.Cu")
		(net "M_A_CPU1_SA_CA<6>")
	)
	(segment
		(start 63.99022 -261.502906)
		(end 63.977012 -261.502906)
		(width 0.101854)
		(layer "F.Cu")
		(net "M_A_CPU1_SA_CA<6>")
	)
	(segment
		(start 73.969372 -256.92989)
		(end 73.907396 -256.955544)
		(width 0.1016)
		(layer "F.Cu")
		(net "M_A_CPU1_SA_CA<6>")
	)
	(segment
		(start 59.272678 -261.066788)
		(end 60.947046 -261.066788)
		(width 0.20066)
		(layer "F.Cu")
		(net "M_A_CPU1_SA_CA<6>")
	)
	(segment
		(start 66.375026 -261.50697)
		(end 66.212212 -261.50697)
		(width 0.20066)
		(layer "F.Cu")
		(net "M_A_CPU1_SA_CA<6>")
	)
	(segment
		(start 73.907396 -256.955544)
		(end 73.895204 -256.985262)
		(width 0.1016)
		(layer "F.Cu")
		(net "M_A_CPU1_SA_CA<6>")
	)
	(segment
		(start 58.847736 -261.49173)
		(end 59.272678 -261.066788)
		(width 0.20066)
		(layer "F.Cu")
		(net "M_A_CPU1_SA_CA<6>")
	)
	(segment
		(start 85.399626 -253.954026)
		(end 84.662518 -253.954026)
		(width 0.088646)
		(layer "F.Cu")
		(net "M_A_CPU1_SA_CA<6>")
	)
	(segment
		(start 66.21018 -261.50697)
		(end 66.19494 -261.49173)
		(width 0.101854)
		(layer "F.Cu")
		(net "M_A_CPU1_SA_CA<6>")
	)
	(segment
		(start 58.704226 -261.49173)
		(end 58.847736 -261.49173)
		(width 0.20066)
		(layer "F.Cu")
		(net "M_A_CPU1_SA_CA<6>")
	)
	(segment
		(start 56.416448 -261.508494)
		(end 56.433212 -261.49173)
		(width 0.101854)
		(layer "F.Cu")
		(net "M_A_CPU1_SA_CA<6>")
	)
	(segment
		(start 55.849012 -261.967472)
		(end 55.950612 -261.865872)
		(width 0.20066)
		(layer "F.Cu")
		(net "M_A_CPU1_SA_CA<6>")
	)
	(segment
		(start 69.135752 -258.956556)
		(end 67.328288 -260.76402)
		(width 0.20066)
		(layer "F.Cu")
		(net "M_A_CPU1_SA_CA<6>")
	)
	(segment
		(start 55.544212 -261.967472)
		(end 55.849012 -261.967472)
		(width 0.20066)
		(layer "F.Cu")
		(net "M_A_CPU1_SA_CA<6>")
	)
	(segment
		(start 66.969132 -260.912864)
		(end 66.375026 -261.50697)
		(width 0.20066)
		(layer "F.Cu")
		(net "M_A_CPU1_SA_CA<6>")
	)
	(segment
		(start 74.807064 -256.621026)
		(end 74.63028 -256.656078)
		(width 0.1016)
		(layer "F.Cu")
		(net "M_A_CPU1_SA_CA<6>")
	)
	(segment
		(start 84.662518 -253.954026)
		(end 83.38947 -255.227074)
		(width 0.088646)
		(layer "F.Cu")
		(net "M_A_CPU1_SA_CA<6>")
	)
	(segment
		(start 56.433212 -261.49173)
		(end 58.643012 -261.49173)
		(width 0.1016)
		(layer "F.Cu")
		(net "M_A_CPU1_SA_CA<6>")
	)
	(segment
		(start 54.643528 -261.066788)
		(end 55.544212 -261.967472)
		(width 0.20066)
		(layer "F.Cu")
		(net "M_A_CPU1_SA_CA<6>")
	)
	(segment
		(start 64.001396 -261.49173)
		(end 63.99022 -261.502906)
		(width 0.101854)
		(layer "F.Cu")
		(net "M_A_CPU1_SA_CA<6>")
	)
	(segment
		(start 66.212212 -261.50697)
		(end 66.21018 -261.50697)
		(width 0.101854)
		(layer "F.Cu")
		(net "M_A_CPU1_SA_CA<6>")
	)
	(segment
		(start 81.995518 -256.621026)
		(end 74.807064 -256.621026)
		(width 0.1016)
		(layer "F.Cu")
		(net "M_A_CPU1_SA_CA<6>")
	)
	(segment
		(start 63.766954 -261.502906)
		(end 63.330836 -261.066788)
		(width 0.20066)
		(layer "F.Cu")
		(net "M_A_CPU1_SA_CA<6>")
	)
	(segment
		(start 85.252306 -255.324356)
		(end 84.78393 -254.957326)
		(width 0.088646)
		(layer "F.Cu")
		(net "M_A_CPU1_SA_CA<5>")
	)
	(segment
		(start 84.09051 -254.957326)
		(end 83.605116 -255.44272)
		(width 0.088646)
		(layer "F.Cu")
		(net "M_A_CPU1_SA_CA<5>")
	)
	(segment
		(start 59.888882 -261.48411)
		(end 59.896502 -261.49173)
		(width 0.101854)
		(layer "F.Cu")
		(net "M_A_CPU1_SA_CA<5>")
	)
	(segment
		(start 59.293252 -261.751572)
		(end 59.560714 -261.48411)
		(width 0.20066)
		(layer "F.Cu")
		(net "M_A_CPU1_SA_CA<5>")
	)
	(segment
		(start 62.072012 -261.49173)
		(end 62.147958 -261.49173)
		(width 0.101854)
		(layer "F.Cu")
		(net "M_A_CPU1_SA_CA<5>")
	)
	(segment
		(start 69.470778 -259.526024)
		(end 67.332352 -261.66445)
		(width 0.20066)
		(layer "F.Cu")
		(net "M_A_CPU1_SA_CA<5>")
	)
	(segment
		(start 83.605116 -255.44272)
		(end 82.12201 -256.925826)
		(width 0.1016)
		(layer "F.Cu")
		(net "M_A_CPU1_SA_CA<5>")
	)
	(segment
		(start 74.260456 -257.542284)
		(end 69.470778 -259.526024)
		(width 0.20066)
		(layer "F.Cu")
		(net "M_A_CPU1_SA_CA<5>")
	)
	(segment
		(start 74.814938 -256.987802)
		(end 74.55916 -257.24358)
		(width 0.1016)
		(layer "F.Cu")
		(net "M_A_CPU1_SA_CA<5>")
	)
	(segment
		(start 59.896502 -261.49173)
		(end 62.072012 -261.49173)
		(width 0.1016)
		(layer "F.Cu")
		(net "M_A_CPU1_SA_CA<5>")
	)
	(segment
		(start 74.964544 -256.925826)
		(end 74.814938 -256.987802)
		(width 0.1016)
		(layer "F.Cu")
		(net "M_A_CPU1_SA_CA<5>")
	)
	(segment
		(start 86.683088 -255.662938)
		(end 86.295738 -255.662938)
		(width 0.088646)
		(layer "F.Cu")
		(net "M_A_CPU1_SA_CA<5>")
	)
	(segment
		(start 86.845648 -255.825498)
		(end 86.683088 -255.662938)
		(width 0.088646)
		(layer "F.Cu")
		(net "M_A_CPU1_SA_CA<5>")
	)
	(segment
		(start 59.146694 -262.17499)
		(end 59.293252 -262.028432)
		(width 0.20066)
		(layer "F.Cu")
		(net "M_A_CPU1_SA_CA<5>")
	)
	(segment
		(start 67.332352 -261.66445)
		(end 67.325748 -261.667244)
		(width 0.20066)
		(layer "F.Cu")
		(net "M_A_CPU1_SA_CA<5>")
	)
	(segment
		(start 85.654896 -255.304036)
		(end 85.622892 -255.33604)
		(width 0.088646)
		(layer "F.Cu")
		(net "M_A_CPU1_SA_CA<5>")
	)
	(segment
		(start 66.723006 -261.916672)
		(end 65.047114 -261.916672)
		(width 0.20066)
		(layer "F.Cu")
		(net "M_A_CPU1_SA_CA<5>")
	)
	(segment
		(start 67.325748 -261.667244)
		(end 66.723006 -261.916672)
		(width 0.20066)
		(layer "F.Cu")
		(net "M_A_CPU1_SA_CA<5>")
	)
	(segment
		(start 63.367412 -261.916672)
		(end 65.047114 -261.916672)
		(width 0.20066)
		(layer "F.Cu")
		(net "M_A_CPU1_SA_CA<5>")
	)
	(segment
		(start 59.822842 -261.48411)
		(end 59.888882 -261.48411)
		(width 0.101854)
		(layer "F.Cu")
		(net "M_A_CPU1_SA_CA<5>")
	)
	(segment
		(start 62.147958 -261.49173)
		(end 62.94247 -261.49173)
		(width 0.20066)
		(layer "F.Cu")
		(net "M_A_CPU1_SA_CA<5>")
	)
	(segment
		(start 82.12201 -256.925826)
		(end 74.964544 -256.925826)
		(width 0.1016)
		(layer "F.Cu")
		(net "M_A_CPU1_SA_CA<5>")
	)
	(segment
		(start 58.505852 -261.916672)
		(end 58.76417 -262.17499)
		(width 0.20066)
		(layer "F.Cu")
		(net "M_A_CPU1_SA_CA<5>")
	)
	(segment
		(start 74.55916 -257.24358)
		(end 74.260456 -257.542284)
		(width 0.20066)
		(layer "F.Cu")
		(net "M_A_CPU1_SA_CA<5>")
	)
	(segment
		(start 86.295738 -255.662938)
		(end 85.954616 -255.321816)
		(width 0.088646)
		(layer "F.Cu")
		(net "M_A_CPU1_SA_CA<5>")
	)
	(segment
		(start 59.293252 -262.028432)
		(end 59.293252 -261.751572)
		(width 0.20066)
		(layer "F.Cu")
		(net "M_A_CPU1_SA_CA<5>")
	)
	(segment
		(start 57.503314 -261.916672)
		(end 58.505852 -261.916672)
		(width 0.20066)
		(layer "F.Cu")
		(net "M_A_CPU1_SA_CA<5>")
	)
	(segment
		(start 62.94247 -261.49173)
		(end 63.367412 -261.916672)
		(width 0.20066)
		(layer "F.Cu")
		(net "M_A_CPU1_SA_CA<5>")
	)
	(segment
		(start 85.954616 -255.321816)
		(end 85.654896 -255.304036)
		(width 0.088646)
		(layer "F.Cu")
		(net "M_A_CPU1_SA_CA<5>")
	)
	(segment
		(start 84.78393 -254.957326)
		(end 84.09051 -254.957326)
		(width 0.088646)
		(layer "F.Cu")
		(net "M_A_CPU1_SA_CA<5>")
	)
	(segment
		(start 58.76417 -262.17499)
		(end 59.146694 -262.17499)
		(width 0.20066)
		(layer "F.Cu")
		(net "M_A_CPU1_SA_CA<5>")
	)
	(segment
		(start 59.560714 -261.48411)
		(end 59.822842 -261.48411)
		(width 0.20066)
		(layer "F.Cu")
		(net "M_A_CPU1_SA_CA<5>")
	)
	(arc
		(start 85.622892 -255.33604)
		(mid 85.450282 -255.382313)
		(end 85.277706 -255.33604)
		(width 0.088646)
		(layer "F.Cu")
		(net "M_A_CPU1_SA_CA<5>")
	)
	(arc
		(start 85.277706 -255.33604)
		(mid 85.265327 -255.329498)
		(end 85.252306 -255.324356)
		(width 0.088646)
		(layer "F.Cu")
		(net "M_A_CPU1_SA_CA<5>")
	)
	(segment
		(start 56.383428 -263.217914)
		(end 56.40959 -263.191752)
		(width 0.101854)
		(layer "F.Cu")
		(net "M_A_CPU1_SA_CA<4>")
	)
	(segment
		(start 64.004444 -262.326374)
		(end 63.977012 -262.326374)
		(width 0.101854)
		(layer "F.Cu")
		(net "M_A_CPU1_SA_CA<4>")
	)
	(segment
		(start 84.951824 -255.385062)
		(end 84.85124 -255.284478)
		(width 0.088646)
		(layer "F.Cu")
		(net "M_A_CPU1_SA_CA<4>")
	)
	(segment
		(start 75.156314 -257.542792)
		(end 75.156314 -257.567938)
		(width 0.1016)
		(layer "F.Cu")
		(net "M_A_CPU1_SA_CA<4>")
	)
	(segment
		(start 63.977012 -262.326374)
		(end 62.30747 -262.326374)
		(width 0.20066)
		(layer "F.Cu")
		(net "M_A_CPU1_SA_CA<4>")
	)
	(segment
		(start 53.403246 -262.76681)
		(end 54.99227 -262.76681)
		(width 0.20066)
		(layer "F.Cu")
		(net "M_A_CPU1_SA_CA<4>")
	)
	(segment
		(start 64.019684 -262.341614)
		(end 64.004444 -262.326374)
		(width 0.101854)
		(layer "F.Cu")
		(net "M_A_CPU1_SA_CA<4>")
	)
	(segment
		(start 75.46848 -257.230626)
		(end 75.156314 -257.542792)
		(width 0.1016)
		(layer "F.Cu")
		(net "M_A_CPU1_SA_CA<4>")
	)
	(segment
		(start 85.551772 -255.730756)
		(end 84.951824 -255.385062)
		(width 0.088646)
		(layer "F.Cu")
		(net "M_A_CPU1_SA_CA<4>")
	)
	(segment
		(start 66.321178 -262.32358)
		(end 66.186812 -262.32358)
		(width 0.20066)
		(layer "F.Cu")
		(net "M_A_CPU1_SA_CA<4>")
	)
	(segment
		(start 66.123058 -262.32358)
		(end 66.105024 -262.341614)
		(width 0.101854)
		(layer "F.Cu")
		(net "M_A_CPU1_SA_CA<4>")
	)
	(segment
		(start 75.156314 -257.567938)
		(end 75.153266 -257.570986)
		(width 0.1016)
		(layer "F.Cu")
		(net "M_A_CPU1_SA_CA<4>")
	)
	(segment
		(start 54.99227 -262.76681)
		(end 55.204614 -262.979154)
		(width 0.20066)
		(layer "F.Cu")
		(net "M_A_CPU1_SA_CA<4>")
	)
	(segment
		(start 75.153266 -257.570986)
		(end 74.651616 -258.072636)
		(width 0.20066)
		(layer "F.Cu")
		(net "M_A_CPU1_SA_CA<4>")
	)
	(segment
		(start 58.704226 -263.191752)
		(end 58.941462 -263.191752)
		(width 0.20066)
		(layer "F.Cu")
		(net "M_A_CPU1_SA_CA<4>")
	)
	(segment
		(start 55.204614 -262.979154)
		(end 55.204614 -263.212326)
		(width 0.20066)
		(layer "F.Cu")
		(net "M_A_CPU1_SA_CA<4>")
	)
	(segment
		(start 66.105024 -262.341614)
		(end 64.019684 -262.341614)
		(width 0.1016)
		(layer "F.Cu")
		(net "M_A_CPU1_SA_CA<4>")
	)
	(segment
		(start 55.459376 -263.467088)
		(end 55.924196 -263.467088)
		(width 0.20066)
		(layer "F.Cu")
		(net "M_A_CPU1_SA_CA<4>")
	)
	(segment
		(start 84.313776 -255.165352)
		(end 83.782662 -255.696466)
		(width 0.088646)
		(layer "F.Cu")
		(net "M_A_CPU1_SA_CA<4>")
	)
	(segment
		(start 62.30747 -262.326374)
		(end 61.867034 -262.76681)
		(width 0.20066)
		(layer "F.Cu")
		(net "M_A_CPU1_SA_CA<4>")
	)
	(segment
		(start 55.204614 -263.212326)
		(end 55.459376 -263.467088)
		(width 0.20066)
		(layer "F.Cu")
		(net "M_A_CPU1_SA_CA<4>")
	)
	(segment
		(start 55.924196 -263.467088)
		(end 56.17337 -263.217914)
		(width 0.20066)
		(layer "F.Cu")
		(net "M_A_CPU1_SA_CA<4>")
	)
	(segment
		(start 56.17337 -263.217914)
		(end 56.37911 -263.217914)
		(width 0.20066)
		(layer "F.Cu")
		(net "M_A_CPU1_SA_CA<4>")
	)
	(segment
		(start 58.668412 -263.191752)
		(end 58.704226 -263.191752)
		(width 0.101854)
		(layer "F.Cu")
		(net "M_A_CPU1_SA_CA<4>")
	)
	(segment
		(start 74.651616 -258.072636)
		(end 69.832982 -260.068314)
		(width 0.20066)
		(layer "F.Cu")
		(net "M_A_CPU1_SA_CA<4>")
	)
	(segment
		(start 56.433212 -263.191752)
		(end 58.668412 -263.191752)
		(width 0.1016)
		(layer "F.Cu")
		(net "M_A_CPU1_SA_CA<4>")
	)
	(segment
		(start 69.832982 -260.068314)
		(end 67.619118 -262.282178)
		(width 0.20066)
		(layer "F.Cu")
		(net "M_A_CPU1_SA_CA<4>")
	)
	(segment
		(start 56.37911 -263.217914)
		(end 56.383428 -263.217914)
		(width 0.101854)
		(layer "F.Cu")
		(net "M_A_CPU1_SA_CA<4>")
	)
	(segment
		(start 58.941462 -263.191752)
		(end 59.366658 -262.766556)
		(width 0.20066)
		(layer "F.Cu")
		(net "M_A_CPU1_SA_CA<4>")
	)
	(segment
		(start 66.186812 -262.32358)
		(end 66.123058 -262.32358)
		(width 0.101854)
		(layer "F.Cu")
		(net "M_A_CPU1_SA_CA<4>")
	)
	(segment
		(start 67.619118 -262.282178)
		(end 67.325748 -262.40359)
		(width 0.20066)
		(layer "F.Cu")
		(net "M_A_CPU1_SA_CA<4>")
	)
	(segment
		(start 66.93789 -262.564372)
		(end 66.56197 -262.564372)
		(width 0.20066)
		(layer "F.Cu")
		(net "M_A_CPU1_SA_CA<4>")
	)
	(segment
		(start 59.366658 -262.766556)
		(end 59.366912 -262.76681)
		(width 0.20066)
		(layer "F.Cu")
		(net "M_A_CPU1_SA_CA<4>")
	)
	(segment
		(start 83.782662 -255.696466)
		(end 82.248502 -257.230626)
		(width 0.1016)
		(layer "F.Cu")
		(net "M_A_CPU1_SA_CA<4>")
	)
	(segment
		(start 67.325748 -262.40359)
		(end 66.93789 -262.564372)
		(width 0.20066)
		(layer "F.Cu")
		(net "M_A_CPU1_SA_CA<4>")
	)
	(segment
		(start 82.248502 -257.230626)
		(end 75.46848 -257.230626)
		(width 0.1016)
		(layer "F.Cu")
		(net "M_A_CPU1_SA_CA<4>")
	)
	(segment
		(start 61.867034 -262.76681)
		(end 60.947046 -262.76681)
		(width 0.20066)
		(layer "F.Cu")
		(net "M_A_CPU1_SA_CA<4>")
	)
	(segment
		(start 84.563712 -255.165352)
		(end 84.313776 -255.165352)
		(width 0.088646)
		(layer "F.Cu")
		(net "M_A_CPU1_SA_CA<4>")
	)
	(segment
		(start 84.85124 -255.284478)
		(end 84.563712 -255.165352)
		(width 0.088646)
		(layer "F.Cu")
		(net "M_A_CPU1_SA_CA<4>")
	)
	(segment
		(start 59.366912 -262.76681)
		(end 60.947046 -262.76681)
		(width 0.20066)
		(layer "F.Cu")
		(net "M_A_CPU1_SA_CA<4>")
	)
	(segment
		(start 66.56197 -262.564372)
		(end 66.321178 -262.32358)
		(width 0.20066)
		(layer "F.Cu")
		(net "M_A_CPU1_SA_CA<4>")
	)
	(segment
		(start 56.40959 -263.191752)
		(end 56.433212 -263.191752)
		(width 0.101854)
		(layer "F.Cu")
		(net "M_A_CPU1_SA_CA<4>")
	)
	(arc
		(start 85.905594 -255.825498)
		(mid 85.722465 -255.80136)
		(end 85.551772 -255.730756)
		(width 0.088646)
		(layer "F.Cu")
		(net "M_A_CPU1_SA_CA<4>")
	)
	(segment
		(start 82.374994 -257.535426)
		(end 76.359512 -257.535426)
		(width 0.1016)
		(layer "F.Cu")
		(net "M_A_CPU1_SA_CA<3>")
	)
	(segment
		(start 85.973666 -256.785872)
		(end 85.973666 -256.433066)
		(width 0.088646)
		(layer "F.Cu")
		(net "M_A_CPU1_SA_CA<3>")
	)
	(segment
		(start 63.41999 -262.95223)
		(end 63.547752 -263.079992)
		(width 0.20066)
		(layer "F.Cu")
		(net "M_A_CPU1_SA_CA<3>")
	)
	(segment
		(start 62.52083 -263.191752)
		(end 62.760352 -262.95223)
		(width 0.20066)
		(layer "F.Cu")
		(net "M_A_CPU1_SA_CA<3>")
	)
	(segment
		(start 84.30895 -256.456434)
		(end 83.453986 -256.456434)
		(width 0.1016)
		(layer "F.Cu")
		(net "M_A_CPU1_SA_CA<3>")
	)
	(segment
		(start 63.547752 -263.344152)
		(end 63.820294 -263.616694)
		(width 0.20066)
		(layer "F.Cu")
		(net "M_A_CPU1_SA_CA<3>")
	)
	(segment
		(start 87.315294 -256.639314)
		(end 86.640416 -256.918968)
		(width 0.088646)
		(layer "F.Cu")
		(net "M_A_CPU1_SA_CA<3>")
	)
	(segment
		(start 63.547752 -263.079992)
		(end 63.547752 -263.344152)
		(width 0.20066)
		(layer "F.Cu")
		(net "M_A_CPU1_SA_CA<3>")
	)
	(segment
		(start 67.408044 -263.530588)
		(end 66.822574 -263.530588)
		(width 0.20066)
		(layer "F.Cu")
		(net "M_A_CPU1_SA_CA<3>")
	)
	(segment
		(start 63.820294 -263.616694)
		(end 65.047114 -263.616694)
		(width 0.20066)
		(layer "F.Cu")
		(net "M_A_CPU1_SA_CA<3>")
	)
	(segment
		(start 59.129676 -263.616694)
		(end 59.568842 -263.177528)
		(width 0.20066)
		(layer "F.Cu")
		(net "M_A_CPU1_SA_CA<3>")
	)
	(segment
		(start 66.822574 -263.530588)
		(end 66.504058 -263.212072)
		(width 0.20066)
		(layer "F.Cu")
		(net "M_A_CPU1_SA_CA<3>")
	)
	(segment
		(start 83.453986 -256.456434)
		(end 82.374994 -257.535426)
		(width 0.1016)
		(layer "F.Cu")
		(net "M_A_CPU1_SA_CA<3>")
	)
	(segment
		(start 85.170772 -256.240026)
		(end 84.954364 -256.456434)
		(width 0.088646)
		(layer "F.Cu")
		(net "M_A_CPU1_SA_CA<3>")
	)
	(segment
		(start 59.822842 -263.177528)
		(end 59.873388 -263.177528)
		(width 0.101854)
		(layer "F.Cu")
		(net "M_A_CPU1_SA_CA<3>")
	)
	(segment
		(start 59.568842 -263.177528)
		(end 59.822842 -263.177528)
		(width 0.20066)
		(layer "F.Cu")
		(net "M_A_CPU1_SA_CA<3>")
	)
	(segment
		(start 59.887612 -263.191752)
		(end 62.097412 -263.191752)
		(width 0.1016)
		(layer "F.Cu")
		(net "M_A_CPU1_SA_CA<3>")
	)
	(segment
		(start 66.031618 -263.212072)
		(end 65.626996 -263.616694)
		(width 0.20066)
		(layer "F.Cu")
		(net "M_A_CPU1_SA_CA<3>")
	)
	(segment
		(start 76.359512 -257.535426)
		(end 75.975718 -257.69443)
		(width 0.1016)
		(layer "F.Cu")
		(net "M_A_CPU1_SA_CA<3>")
	)
	(segment
		(start 57.503314 -263.616694)
		(end 59.129676 -263.616694)
		(width 0.20066)
		(layer "F.Cu")
		(net "M_A_CPU1_SA_CA<3>")
	)
	(segment
		(start 85.780626 -256.240026)
		(end 85.170772 -256.240026)
		(width 0.088646)
		(layer "F.Cu")
		(net "M_A_CPU1_SA_CA<3>")
	)
	(segment
		(start 86.640416 -256.918968)
		(end 86.562692 -256.963672)
		(width 0.088646)
		(layer "F.Cu")
		(net "M_A_CPU1_SA_CA<3>")
	)
	(segment
		(start 86.086696 -256.898902)
		(end 85.973666 -256.785872)
		(width 0.088646)
		(layer "F.Cu")
		(net "M_A_CPU1_SA_CA<3>")
	)
	(segment
		(start 62.760352 -262.95223)
		(end 63.41999 -262.95223)
		(width 0.20066)
		(layer "F.Cu")
		(net "M_A_CPU1_SA_CA<3>")
	)
	(segment
		(start 62.097412 -263.191752)
		(end 62.147958 -263.191752)
		(width 0.101854)
		(layer "F.Cu")
		(net "M_A_CPU1_SA_CA<3>")
	)
	(segment
		(start 75.975718 -257.69443)
		(end 75.75169 -257.918458)
		(width 0.1016)
		(layer "F.Cu")
		(net "M_A_CPU1_SA_CA<3>")
	)
	(segment
		(start 84.954364 -256.456434)
		(end 84.30895 -256.456434)
		(width 0.088646)
		(layer "F.Cu")
		(net "M_A_CPU1_SA_CA<3>")
	)
	(segment
		(start 65.626996 -263.616694)
		(end 65.047114 -263.616694)
		(width 0.20066)
		(layer "F.Cu")
		(net "M_A_CPU1_SA_CA<3>")
	)
	(segment
		(start 66.504058 -263.212072)
		(end 66.031618 -263.212072)
		(width 0.20066)
		(layer "F.Cu")
		(net "M_A_CPU1_SA_CA<3>")
	)
	(segment
		(start 75.75169 -257.918458)
		(end 74.915776 -258.754372)
		(width 0.20066)
		(layer "F.Cu")
		(net "M_A_CPU1_SA_CA<3>")
	)
	(segment
		(start 86.18855 -256.963672)
		(end 86.188296 -256.963672)
		(width 0.088646)
		(layer "F.Cu")
		(net "M_A_CPU1_SA_CA<3>")
	)
	(segment
		(start 74.915776 -258.754372)
		(end 70.25259 -260.686042)
		(width 0.20066)
		(layer "F.Cu")
		(net "M_A_CPU1_SA_CA<3>")
	)
	(segment
		(start 85.973666 -256.433066)
		(end 85.780626 -256.240026)
		(width 0.088646)
		(layer "F.Cu")
		(net "M_A_CPU1_SA_CA<3>")
	)
	(segment
		(start 62.147958 -263.191752)
		(end 62.52083 -263.191752)
		(width 0.20066)
		(layer "F.Cu")
		(net "M_A_CPU1_SA_CA<3>")
	)
	(segment
		(start 70.25259 -260.686042)
		(end 67.408044 -263.530588)
		(width 0.20066)
		(layer "F.Cu")
		(net "M_A_CPU1_SA_CA<3>")
	)
	(segment
		(start 59.873388 -263.177528)
		(end 59.887612 -263.191752)
		(width 0.101854)
		(layer "F.Cu")
		(net "M_A_CPU1_SA_CA<3>")
	)
	(arc
		(start 86.562692 -256.963672)
		(mid 86.375638 -257.013756)
		(end 86.18855 -256.963672)
		(width 0.088646)
		(layer "F.Cu")
		(net "M_A_CPU1_SA_CA<3>")
	)
	(arc
		(start 86.188296 -256.963672)
		(mid 86.136778 -256.932413)
		(end 86.086696 -256.898902)
		(width 0.088646)
		(layer "F.Cu")
		(net "M_A_CPU1_SA_CA<3>")
	)
	(segment
		(start 55.674768 -265.138916)
		(end 55.906162 -264.907522)
		(width 0.20066)
		(layer "F.Cu")
		(net "M_A_CPU1_SA_CA<2>")
	)
	(segment
		(start 85.150706 -256.639314)
		(end 85.435694 -256.639314)
		(width 0.088646)
		(layer "F.Cu")
		(net "M_A_CPU1_SA_CA<2>")
	)
	(segment
		(start 85.023706 -256.766314)
		(end 85.150706 -256.639314)
		(width 0.088646)
		(layer "F.Cu")
		(net "M_A_CPU1_SA_CA<2>")
	)
	(segment
		(start 62.013846 -264.466578)
		(end 62.452758 -264.027666)
		(width 0.20066)
		(layer "F.Cu")
		(net "M_A_CPU1_SA_CA<2>")
	)
	(segment
		(start 67.672966 -264.17016)
		(end 70.614286 -261.22884)
		(width 0.20066)
		(layer "F.Cu")
		(net "M_A_CPU1_SA_CA<2>")
	)
	(segment
		(start 76.775818 -258.011676)
		(end 76.947268 -257.840226)
		(width 0.1016)
		(layer "F.Cu")
		(net "M_A_CPU1_SA_CA<2>")
	)
	(segment
		(start 66.17716 -264.041636)
		(end 66.19113 -264.027666)
		(width 0.101854)
		(layer "F.Cu")
		(net "M_A_CPU1_SA_CA<2>")
	)
	(segment
		(start 66.212212 -264.027666)
		(end 66.469006 -264.027666)
		(width 0.20066)
		(layer "F.Cu")
		(net "M_A_CPU1_SA_CA<2>")
	)
	(segment
		(start 55.906162 -264.907522)
		(end 56.37911 -264.907522)
		(width 0.20066)
		(layer "F.Cu")
		(net "M_A_CPU1_SA_CA<2>")
	)
	(segment
		(start 56.393588 -264.907522)
		(end 56.40959 -264.89152)
		(width 0.101854)
		(layer "F.Cu")
		(net "M_A_CPU1_SA_CA<2>")
	)
	(segment
		(start 63.977012 -264.027666)
		(end 64.00165 -264.027666)
		(width 0.101854)
		(layer "F.Cu")
		(net "M_A_CPU1_SA_CA<2>")
	)
	(segment
		(start 82.501486 -257.840226)
		(end 83.575398 -256.766314)
		(width 0.1016)
		(layer "F.Cu")
		(net "M_A_CPU1_SA_CA<2>")
	)
	(segment
		(start 55.087012 -264.71245)
		(end 55.087012 -264.984484)
		(width 0.20066)
		(layer "F.Cu")
		(net "M_A_CPU1_SA_CA<2>")
	)
	(segment
		(start 76.947268 -257.840226)
		(end 82.501486 -257.840226)
		(width 0.1016)
		(layer "F.Cu")
		(net "M_A_CPU1_SA_CA<2>")
	)
	(segment
		(start 70.614286 -261.22884)
		(end 70.874382 -261.121144)
		(width 0.20066)
		(layer "F.Cu")
		(net "M_A_CPU1_SA_CA<2>")
	)
	(segment
		(start 70.87489 -261.120636)
		(end 75.641454 -259.14604)
		(width 0.20066)
		(layer "F.Cu")
		(net "M_A_CPU1_SA_CA<2>")
	)
	(segment
		(start 56.40959 -264.89152)
		(end 56.433212 -264.89152)
		(width 0.101854)
		(layer "F.Cu")
		(net "M_A_CPU1_SA_CA<2>")
	)
	(segment
		(start 66.6115 -264.17016)
		(end 67.672966 -264.17016)
		(width 0.20066)
		(layer "F.Cu")
		(net "M_A_CPU1_SA_CA<2>")
	)
	(segment
		(start 58.704226 -264.89152)
		(end 58.941462 -264.89152)
		(width 0.20066)
		(layer "F.Cu")
		(net "M_A_CPU1_SA_CA<2>")
	)
	(segment
		(start 55.241444 -265.138916)
		(end 55.674768 -265.138916)
		(width 0.20066)
		(layer "F.Cu")
		(net "M_A_CPU1_SA_CA<2>")
	)
	(segment
		(start 62.452758 -264.027666)
		(end 63.977012 -264.027666)
		(width 0.20066)
		(layer "F.Cu")
		(net "M_A_CPU1_SA_CA<2>")
	)
	(segment
		(start 70.874382 -261.121144)
		(end 70.87489 -261.120636)
		(width 0.20066)
		(layer "F.Cu")
		(net "M_A_CPU1_SA_CA<2>")
	)
	(segment
		(start 55.087012 -264.984484)
		(end 55.241444 -265.138916)
		(width 0.20066)
		(layer "F.Cu")
		(net "M_A_CPU1_SA_CA<2>")
	)
	(segment
		(start 56.37911 -264.907522)
		(end 56.393588 -264.907522)
		(width 0.101854)
		(layer "F.Cu")
		(net "M_A_CPU1_SA_CA<2>")
	)
	(segment
		(start 64.00165 -264.027666)
		(end 64.01562 -264.041636)
		(width 0.101854)
		(layer "F.Cu")
		(net "M_A_CPU1_SA_CA<2>")
	)
	(segment
		(start 83.575398 -256.766314)
		(end 84.38515 -256.766314)
		(width 0.1016)
		(layer "F.Cu")
		(net "M_A_CPU1_SA_CA<2>")
	)
	(segment
		(start 53.403246 -264.466578)
		(end 54.84114 -264.466578)
		(width 0.20066)
		(layer "F.Cu")
		(net "M_A_CPU1_SA_CA<2>")
	)
	(segment
		(start 64.01562 -264.041636)
		(end 66.17716 -264.041636)
		(width 0.1016)
		(layer "F.Cu")
		(net "M_A_CPU1_SA_CA<2>")
	)
	(segment
		(start 59.366658 -264.466324)
		(end 59.366912 -264.466578)
		(width 0.20066)
		(layer "F.Cu")
		(net "M_A_CPU1_SA_CA<2>")
	)
	(segment
		(start 75.641454 -259.14604)
		(end 76.775818 -258.011676)
		(width 0.20066)
		(layer "F.Cu")
		(net "M_A_CPU1_SA_CA<2>")
	)
	(segment
		(start 54.84114 -264.466578)
		(end 55.087012 -264.71245)
		(width 0.20066)
		(layer "F.Cu")
		(net "M_A_CPU1_SA_CA<2>")
	)
	(segment
		(start 66.469006 -264.027666)
		(end 66.6115 -264.17016)
		(width 0.20066)
		(layer "F.Cu")
		(net "M_A_CPU1_SA_CA<2>")
	)
	(segment
		(start 84.38515 -256.766314)
		(end 85.023706 -256.766314)
		(width 0.088646)
		(layer "F.Cu")
		(net "M_A_CPU1_SA_CA<2>")
	)
	(segment
		(start 59.366912 -264.466578)
		(end 60.947046 -264.466578)
		(width 0.20066)
		(layer "F.Cu")
		(net "M_A_CPU1_SA_CA<2>")
	)
	(segment
		(start 58.668412 -264.89152)
		(end 58.704226 -264.89152)
		(width 0.101854)
		(layer "F.Cu")
		(net "M_A_CPU1_SA_CA<2>")
	)
	(segment
		(start 60.947046 -264.466578)
		(end 62.013846 -264.466578)
		(width 0.20066)
		(layer "F.Cu")
		(net "M_A_CPU1_SA_CA<2>")
	)
	(segment
		(start 56.433212 -264.89152)
		(end 58.668412 -264.89152)
		(width 0.1016)
		(layer "F.Cu")
		(net "M_A_CPU1_SA_CA<2>")
	)
	(segment
		(start 66.19113 -264.027666)
		(end 66.212212 -264.027666)
		(width 0.101854)
		(layer "F.Cu")
		(net "M_A_CPU1_SA_CA<2>")
	)
	(segment
		(start 58.941462 -264.89152)
		(end 59.366658 -264.466324)
		(width 0.20066)
		(layer "F.Cu")
		(net "M_A_CPU1_SA_CA<2>")
	)
	(segment
		(start 57.503314 -265.316716)
		(end 59.129676 -265.316716)
		(width 0.20066)
		(layer "F.Cu")
		(net "M_A_CPU1_SA_CA<1>")
	)
	(segment
		(start 64.133476 -265.316716)
		(end 65.047114 -265.316716)
		(width 0.20066)
		(layer "F.Cu")
		(net "M_A_CPU1_SA_CA<1>")
	)
	(segment
		(start 84.966048 -257.078734)
		(end 84.703158 -257.078734)
		(width 0.088646)
		(layer "F.Cu")
		(net "M_A_CPU1_SA_CA<1>")
	)
	(segment
		(start 59.85637 -264.873232)
		(end 59.874658 -264.89152)
		(width 0.101854)
		(layer "F.Cu")
		(net "M_A_CPU1_SA_CA<1>")
	)
	(segment
		(start 66.441828 -264.809732)
		(end 66.109088 -265.142472)
		(width 0.20066)
		(layer "F.Cu")
		(net "M_A_CPU1_SA_CA<1>")
	)
	(segment
		(start 59.57316 -264.873232)
		(end 59.822842 -264.873232)
		(width 0.20066)
		(layer "F.Cu")
		(net "M_A_CPU1_SA_CA<1>")
	)
	(segment
		(start 87.785194 -257.45313)
		(end 87.414862 -257.082798)
		(width 0.088646)
		(layer "F.Cu")
		(net "M_A_CPU1_SA_CA<1>")
	)
	(segment
		(start 76.169774 -259.619496)
		(end 71.237348 -261.662926)
		(width 0.20066)
		(layer "F.Cu")
		(net "M_A_CPU1_SA_CA<1>")
	)
	(segment
		(start 62.575186 -265.201146)
		(end 62.90183 -265.201146)
		(width 0.20066)
		(layer "F.Cu")
		(net "M_A_CPU1_SA_CA<1>")
	)
	(segment
		(start 62.90183 -265.201146)
		(end 63.330582 -264.772394)
		(width 0.20066)
		(layer "F.Cu")
		(net "M_A_CPU1_SA_CA<1>")
	)
	(segment
		(start 77.352906 -258.436364)
		(end 76.169774 -259.619496)
		(width 0.20066)
		(layer "F.Cu")
		(net "M_A_CPU1_SA_CA<1>")
	)
	(segment
		(start 62.136274 -264.89152)
		(end 62.147958 -264.89152)
		(width 0.101854)
		(layer "F.Cu")
		(net "M_A_CPU1_SA_CA<1>")
	)
	(segment
		(start 71.23684 -261.663434)
		(end 70.976236 -261.771384)
		(width 0.20066)
		(layer "F.Cu")
		(net "M_A_CPU1_SA_CA<1>")
	)
	(segment
		(start 66.109088 -265.142472)
		(end 65.785492 -265.142472)
		(width 0.20066)
		(layer "F.Cu")
		(net "M_A_CPU1_SA_CA<1>")
	)
	(segment
		(start 85.16366 -257.134868)
		(end 85.153246 -257.128772)
		(width 0.088646)
		(layer "F.Cu")
		(net "M_A_CPU1_SA_CA<1>")
	)
	(segment
		(start 59.129676 -265.316716)
		(end 59.57316 -264.873232)
		(width 0.20066)
		(layer "F.Cu")
		(net "M_A_CPU1_SA_CA<1>")
	)
	(segment
		(start 62.147958 -264.89152)
		(end 62.26556 -264.89152)
		(width 0.20066)
		(layer "F.Cu")
		(net "M_A_CPU1_SA_CA<1>")
	)
	(segment
		(start 87.414862 -257.082798)
		(end 86.901274 -257.082798)
		(width 0.088646)
		(layer "F.Cu")
		(net "M_A_CPU1_SA_CA<1>")
	)
	(segment
		(start 65.785492 -265.142472)
		(end 65.611248 -265.316716)
		(width 0.20066)
		(layer "F.Cu")
		(net "M_A_CPU1_SA_CA<1>")
	)
	(segment
		(start 86.103206 -257.134868)
		(end 86.092792 -257.128772)
		(width 0.088646)
		(layer "F.Cu")
		(net "M_A_CPU1_SA_CA<1>")
	)
	(segment
		(start 62.26556 -264.89152)
		(end 62.575186 -265.201146)
		(width 0.20066)
		(layer "F.Cu")
		(net "M_A_CPU1_SA_CA<1>")
	)
	(segment
		(start 70.976236 -261.771384)
		(end 67.937888 -264.809732)
		(width 0.20066)
		(layer "F.Cu")
		(net "M_A_CPU1_SA_CA<1>")
	)
	(segment
		(start 65.611248 -265.316716)
		(end 65.047114 -265.316716)
		(width 0.20066)
		(layer "F.Cu")
		(net "M_A_CPU1_SA_CA<1>")
	)
	(segment
		(start 84.703158 -257.078734)
		(end 83.69427 -257.078734)
		(width 0.1016)
		(layer "F.Cu")
		(net "M_A_CPU1_SA_CA<1>")
	)
	(segment
		(start 67.937888 -264.809732)
		(end 66.441828 -264.809732)
		(width 0.20066)
		(layer "F.Cu")
		(net "M_A_CPU1_SA_CA<1>")
	)
	(segment
		(start 83.69427 -257.078734)
		(end 82.627978 -258.145026)
		(width 0.1016)
		(layer "F.Cu")
		(net "M_A_CPU1_SA_CA<1>")
	)
	(segment
		(start 82.627978 -258.145026)
		(end 77.644244 -258.145026)
		(width 0.1016)
		(layer "F.Cu")
		(net "M_A_CPU1_SA_CA<1>")
	)
	(segment
		(start 63.589154 -264.772394)
		(end 64.133476 -265.316716)
		(width 0.20066)
		(layer "F.Cu")
		(net "M_A_CPU1_SA_CA<1>")
	)
	(segment
		(start 59.874658 -264.89152)
		(end 62.136274 -264.89152)
		(width 0.1016)
		(layer "F.Cu")
		(net "M_A_CPU1_SA_CA<1>")
	)
	(segment
		(start 63.330582 -264.772394)
		(end 63.589154 -264.772394)
		(width 0.20066)
		(layer "F.Cu")
		(net "M_A_CPU1_SA_CA<1>")
	)
	(segment
		(start 59.822842 -264.873232)
		(end 59.85637 -264.873232)
		(width 0.101854)
		(layer "F.Cu")
		(net "M_A_CPU1_SA_CA<1>")
	)
	(segment
		(start 77.644244 -258.145026)
		(end 77.352906 -258.436364)
		(width 0.1016)
		(layer "F.Cu")
		(net "M_A_CPU1_SA_CA<1>")
	)
	(segment
		(start 71.237348 -261.662926)
		(end 71.23684 -261.663434)
		(width 0.20066)
		(layer "F.Cu")
		(net "M_A_CPU1_SA_CA<1>")
	)
	(arc
		(start 86.092792 -257.128772)
		(mid 85.905594 -257.078629)
		(end 85.718396 -257.128772)
		(width 0.088646)
		(layer "F.Cu")
		(net "M_A_CPU1_SA_CA<1>")
	)
	(arc
		(start 85.153246 -257.128772)
		(mid 85.062939 -257.091443)
		(end 84.966048 -257.078734)
		(width 0.088646)
		(layer "F.Cu")
		(net "M_A_CPU1_SA_CA<1>")
	)
	(arc
		(start 86.65845 -257.128772)
		(mid 86.381637 -257.204642)
		(end 86.103206 -257.134868)
		(width 0.088646)
		(layer "F.Cu")
		(net "M_A_CPU1_SA_CA<1>")
	)
	(arc
		(start 85.718396 -257.128772)
		(mid 85.441837 -257.204515)
		(end 85.16366 -257.134868)
		(width 0.088646)
		(layer "F.Cu")
		(net "M_A_CPU1_SA_CA<1>")
	)
	(arc
		(start 86.901274 -257.082798)
		(mid 86.775963 -257.085184)
		(end 86.65845 -257.128772)
		(width 0.088646)
		(layer "F.Cu")
		(net "M_A_CPU1_SA_CA<1>")
	)
	(segment
		(start 76.167742 -260.31317)
		(end 76.167996 -260.312662)
		(width 0.20066)
		(layer "F.Cu")
		(net "M_A_CPU1_SA_CA<0>")
	)
	(segment
		(start 56.471566 -265.741658)
		(end 58.668412 -265.741658)
		(width 0.1016)
		(layer "F.Cu")
		(net "M_A_CPU1_SA_CA<0>")
	)
	(segment
		(start 60.947046 -266.1666)
		(end 62.14618 -266.1666)
		(width 0.20066)
		(layer "F.Cu")
		(net "M_A_CPU1_SA_CA<0>")
	)
	(segment
		(start 66.533268 -265.579606)
		(end 67.866514 -265.579606)
		(width 0.20066)
		(layer "F.Cu")
		(net "M_A_CPU1_SA_CA<0>")
	)
	(segment
		(start 55.899812 -265.868658)
		(end 56.071262 -265.697208)
		(width 0.20066)
		(layer "F.Cu")
		(net "M_A_CPU1_SA_CA<0>")
	)
	(segment
		(start 71.33844 -262.313674)
		(end 71.599044 -262.205724)
		(width 0.20066)
		(layer "F.Cu")
		(net "M_A_CPU1_SA_CA<0>")
	)
	(segment
		(start 60.137294 -266.1666)
		(end 60.947046 -266.1666)
		(width 0.20066)
		(layer "F.Cu")
		(net "M_A_CPU1_SA_CA<0>")
	)
	(segment
		(start 59.712352 -265.741658)
		(end 60.137294 -266.1666)
		(width 0.20066)
		(layer "F.Cu")
		(net "M_A_CPU1_SA_CA<0>")
	)
	(segment
		(start 78.246478 -258.449826)
		(end 82.75447 -258.449826)
		(width 0.1016)
		(layer "F.Cu")
		(net "M_A_CPU1_SA_CA<0>")
	)
	(segment
		(start 54.69382 -266.1666)
		(end 55.018178 -266.490958)
		(width 0.20066)
		(layer "F.Cu")
		(net "M_A_CPU1_SA_CA<0>")
	)
	(segment
		(start 78.072996 -258.623308)
		(end 78.246478 -258.449826)
		(width 0.1016)
		(layer "F.Cu")
		(net "M_A_CPU1_SA_CA<0>")
	)
	(segment
		(start 56.37911 -265.697208)
		(end 56.427116 -265.697208)
		(width 0.101854)
		(layer "F.Cu")
		(net "M_A_CPU1_SA_CA<0>")
	)
	(segment
		(start 66.397124 -265.71575)
		(end 66.533268 -265.579606)
		(width 0.20066)
		(layer "F.Cu")
		(net "M_A_CPU1_SA_CA<0>")
	)
	(segment
		(start 83.751166 -257.45313)
		(end 84.966048 -257.45313)
		(width 0.1016)
		(layer "F.Cu")
		(net "M_A_CPU1_SA_CA<0>")
	)
	(segment
		(start 62.588902 -265.723878)
		(end 63.977012 -265.723878)
		(width 0.20066)
		(layer "F.Cu")
		(net "M_A_CPU1_SA_CA<0>")
	)
	(segment
		(start 62.14618 -266.1666)
		(end 62.588902 -265.723878)
		(width 0.20066)
		(layer "F.Cu")
		(net "M_A_CPU1_SA_CA<0>")
	)
	(segment
		(start 58.668412 -265.741658)
		(end 58.704226 -265.741658)
		(width 0.101854)
		(layer "F.Cu")
		(net "M_A_CPU1_SA_CA<0>")
	)
	(segment
		(start 63.977012 -265.723878)
		(end 64.007492 -265.723878)
		(width 0.101854)
		(layer "F.Cu")
		(net "M_A_CPU1_SA_CA<0>")
	)
	(segment
		(start 68.21805 -265.434064)
		(end 71.33844 -262.313674)
		(width 0.20066)
		(layer "F.Cu")
		(net "M_A_CPU1_SA_CA<0>")
	)
	(segment
		(start 76.167996 -260.312662)
		(end 76.536042 -260.160262)
		(width 0.20066)
		(layer "F.Cu")
		(net "M_A_CPU1_SA_CA<0>")
	)
	(segment
		(start 53.403246 -266.1666)
		(end 54.69382 -266.1666)
		(width 0.20066)
		(layer "F.Cu")
		(net "M_A_CPU1_SA_CA<0>")
	)
	(segment
		(start 58.704226 -265.741658)
		(end 59.712352 -265.741658)
		(width 0.20066)
		(layer "F.Cu")
		(net "M_A_CPU1_SA_CA<0>")
	)
	(segment
		(start 56.427116 -265.697208)
		(end 56.471566 -265.741658)
		(width 0.101854)
		(layer "F.Cu")
		(net "M_A_CPU1_SA_CA<0>")
	)
	(segment
		(start 55.414926 -266.490958)
		(end 55.899812 -266.006072)
		(width 0.20066)
		(layer "F.Cu")
		(net "M_A_CPU1_SA_CA<0>")
	)
	(segment
		(start 66.173604 -265.741658)
		(end 66.199512 -265.71575)
		(width 0.101854)
		(layer "F.Cu")
		(net "M_A_CPU1_SA_CA<0>")
	)
	(segment
		(start 82.75447 -258.449826)
		(end 83.751166 -257.45313)
		(width 0.1016)
		(layer "F.Cu")
		(net "M_A_CPU1_SA_CA<0>")
	)
	(segment
		(start 71.599044 -262.205724)
		(end 71.599552 -262.205216)
		(width 0.20066)
		(layer "F.Cu")
		(net "M_A_CPU1_SA_CA<0>")
	)
	(segment
		(start 56.071262 -265.697208)
		(end 56.37911 -265.697208)
		(width 0.20066)
		(layer "F.Cu")
		(net "M_A_CPU1_SA_CA<0>")
	)
	(segment
		(start 67.866514 -265.579606)
		(end 68.21805 -265.434064)
		(width 0.20066)
		(layer "F.Cu")
		(net "M_A_CPU1_SA_CA<0>")
	)
	(segment
		(start 76.536042 -260.160262)
		(end 78.072996 -258.623308)
		(width 0.20066)
		(layer "F.Cu")
		(net "M_A_CPU1_SA_CA<0>")
	)
	(segment
		(start 55.018178 -266.490958)
		(end 55.414926 -266.490958)
		(width 0.20066)
		(layer "F.Cu")
		(net "M_A_CPU1_SA_CA<0>")
	)
	(segment
		(start 55.899812 -266.006072)
		(end 55.899812 -265.868658)
		(width 0.20066)
		(layer "F.Cu")
		(net "M_A_CPU1_SA_CA<0>")
	)
	(segment
		(start 66.199512 -265.71575)
		(end 66.212212 -265.71575)
		(width 0.101854)
		(layer "F.Cu")
		(net "M_A_CPU1_SA_CA<0>")
	)
	(segment
		(start 64.007492 -265.723878)
		(end 64.025272 -265.741658)
		(width 0.101854)
		(layer "F.Cu")
		(net "M_A_CPU1_SA_CA<0>")
	)
	(segment
		(start 64.025272 -265.741658)
		(end 66.173604 -265.741658)
		(width 0.1016)
		(layer "F.Cu")
		(net "M_A_CPU1_SA_CA<0>")
	)
	(segment
		(start 66.212212 -265.71575)
		(end 66.397124 -265.71575)
		(width 0.20066)
		(layer "F.Cu")
		(net "M_A_CPU1_SA_CA<0>")
	)
	(segment
		(start 71.599552 -262.205216)
		(end 76.167742 -260.31317)
		(width 0.20066)
		(layer "F.Cu")
		(net "M_A_CPU1_SA_CA<0>")
	)
	(segment
		(start 83.97875 -251.420376)
		(end 83.65871 -251.420376)
		(width 0.20066)
		(layer "F.Cu")
		(net "M_A_CPU1_CLK_DP<1>")
	)
	(segment
		(start 86.261702 -250.864878)
		(end 85.775038 -251.351542)
		(width 0.088646)
		(layer "F.Cu")
		(net "M_A_CPU1_CLK_DP<1>")
	)
	(segment
		(start 72.703182 -255.919732)
		(end 72.146668 -256.150364)
		(width 0.20066)
		(layer "F.Cu")
		(net "M_A_CPU1_CLK_DP<1>")
	)
	(segment
		(start 79.82585 -255.594866)
		(end 73.16216 -255.594866)
		(width 0.20066)
		(layer "F.Cu")
		(net "M_A_CPU1_CLK_DP<1>")
	)
	(segment
		(start 70.641718 -256.639314)
		(end 70.085712 -256.869438)
		(width 0.20066)
		(layer "F.Cu")
		(net "M_A_CPU1_CLK_DP<1>")
	)
	(segment
		(start 86.735666 -250.155964)
		(end 87.046562 -250.155964)
		(width 0.088646)
		(layer "F.Cu")
		(net "M_A_CPU1_CLK_DP<1>")
	)
	(segment
		(start 72.146668 -256.150364)
		(end 71.984108 -256.083054)
		(width 0.20066)
		(layer "F.Cu")
		(net "M_A_CPU1_CLK_DP<1>")
	)
	(segment
		(start 86.931754 -249.836686)
		(end 86.924388 -249.832368)
		(width 0.088646)
		(layer "F.Cu")
		(net "M_A_CPU1_CLK_DP<1>")
	)
	(segment
		(start 73.16216 -255.594866)
		(end 72.770492 -255.757172)
		(width 0.20066)
		(layer "F.Cu")
		(net "M_A_CPU1_CLK_DP<1>")
	)
	(segment
		(start 72.770492 -255.757172)
		(end 72.703182 -255.919732)
		(width 0.20066)
		(layer "F.Cu")
		(net "M_A_CPU1_CLK_DP<1>")
	)
	(segment
		(start 71.360792 -256.475992)
		(end 70.804278 -256.706624)
		(width 0.20066)
		(layer "F.Cu")
		(net "M_A_CPU1_CLK_DP<1>")
	)
	(segment
		(start 70.085712 -256.869438)
		(end 70.018402 -257.032252)
		(width 0.20066)
		(layer "F.Cu")
		(net "M_A_CPU1_CLK_DP<1>")
	)
	(segment
		(start 70.804278 -256.706624)
		(end 70.641718 -256.639314)
		(width 0.20066)
		(layer "F.Cu")
		(net "M_A_CPU1_CLK_DP<1>")
	)
	(segment
		(start 84.00669 -251.420376)
		(end 83.97875 -251.420376)
		(width 0.088646)
		(layer "F.Cu")
		(net "M_A_CPU1_CLK_DP<1>")
	)
	(segment
		(start 69.299328 -257.19532)
		(end 68.812918 -257.396742)
		(width 0.20066)
		(layer "F.Cu")
		(net "M_A_CPU1_CLK_DP<1>")
	)
	(segment
		(start 71.984108 -256.083054)
		(end 71.428102 -256.313432)
		(width 0.20066)
		(layer "F.Cu")
		(net "M_A_CPU1_CLK_DP<1>")
	)
	(segment
		(start 82.41284 -253.007876)
		(end 79.82585 -255.594866)
		(width 0.20066)
		(layer "F.Cu")
		(net "M_A_CPU1_CLK_DP<1>")
	)
	(segment
		(start 87.046562 -250.155964)
		(end 87.10549 -250.097036)
		(width 0.088646)
		(layer "F.Cu")
		(net "M_A_CPU1_CLK_DP<1>")
	)
	(segment
		(start 86.361016 -250.155964)
		(end 86.361016 -250.625102)
		(width 0.088646)
		(layer "F.Cu")
		(net "M_A_CPU1_CLK_DP<1>")
	)
	(segment
		(start 66.220848 -259.988812)
		(end 65.831212 -259.988812)
		(width 0.20066)
		(layer "F.Cu")
		(net "M_A_CPU1_CLK_DP<1>")
	)
	(segment
		(start 68.812918 -257.396742)
		(end 66.220848 -259.988812)
		(width 0.20066)
		(layer "F.Cu")
		(net "M_A_CPU1_CLK_DP<1>")
	)
	(segment
		(start 65.831212 -259.988812)
		(end 65.603374 -260.21665)
		(width 0.20066)
		(layer "F.Cu")
		(net "M_A_CPU1_CLK_DP<1>")
	)
	(segment
		(start 84.075524 -251.351542)
		(end 84.00669 -251.420376)
		(width 0.088646)
		(layer "F.Cu")
		(net "M_A_CPU1_CLK_DP<1>")
	)
	(segment
		(start 83.65871 -251.420376)
		(end 83.100672 -251.978668)
		(width 0.20066)
		(layer "F.Cu")
		(net "M_A_CPU1_CLK_DP<1>")
	)
	(segment
		(start 71.428102 -256.313432)
		(end 71.360792 -256.475992)
		(width 0.20066)
		(layer "F.Cu")
		(net "M_A_CPU1_CLK_DP<1>")
	)
	(segment
		(start 86.924388 -249.832368)
		(end 86.922864 -249.831606)
		(width 0.088646)
		(layer "F.Cu")
		(net "M_A_CPU1_CLK_DP<1>")
	)
	(segment
		(start 65.603374 -260.21665)
		(end 65.047114 -260.21665)
		(width 0.20066)
		(layer "F.Cu")
		(net "M_A_CPU1_CLK_DP<1>")
	)
	(segment
		(start 86.361016 -250.625102)
		(end 86.261702 -250.864878)
		(width 0.088646)
		(layer "F.Cu")
		(net "M_A_CPU1_CLK_DP<1>")
	)
	(segment
		(start 83.100672 -251.978668)
		(end 82.41284 -253.007876)
		(width 0.20066)
		(layer "F.Cu")
		(net "M_A_CPU1_CLK_DP<1>")
	)
	(segment
		(start 85.775038 -251.351542)
		(end 84.075524 -251.351542)
		(width 0.088646)
		(layer "F.Cu")
		(net "M_A_CPU1_CLK_DP<1>")
	)
	(segment
		(start 86.548468 -249.831606)
		(end 86.539578 -249.836686)
		(width 0.088646)
		(layer "F.Cu")
		(net "M_A_CPU1_CLK_DP<1>")
	)
	(segment
		(start 70.018402 -257.032252)
		(end 69.461888 -257.262884)
		(width 0.20066)
		(layer "F.Cu")
		(net "M_A_CPU1_CLK_DP<1>")
	)
	(segment
		(start 69.461888 -257.262884)
		(end 69.299328 -257.19532)
		(width 0.20066)
		(layer "F.Cu")
		(net "M_A_CPU1_CLK_DP<1>")
	)
	(arc
		(start 87.10549 -250.097036)
		(mid 87.047147 -249.947813)
		(end 86.931754 -249.836686)
		(width 0.088646)
		(layer "F.Cu")
		(net "M_A_CPU1_CLK_DP<1>")
	)
	(arc
		(start 86.539578 -249.836686)
		(mid 86.408664 -249.973046)
		(end 86.361016 -250.155964)
		(width 0.088646)
		(layer "F.Cu")
		(net "M_A_CPU1_CLK_DP<1>")
	)
	(arc
		(start 86.922864 -249.831606)
		(mid 86.735666 -249.781463)
		(end 86.548468 -249.831606)
		(width 0.088646)
		(layer "F.Cu")
		(net "M_A_CPU1_CLK_DP<1>")
	)
	(segment
		(start 58.297826 -259.968238)
		(end 58.049414 -260.21665)
		(width 0.20066)
		(layer "F.Cu")
		(net "M_A_CPU1_CLK_DP<0>")
	)
	(segment
		(start 83.316572 -250.38939)
		(end 81.843372 -251.86259)
		(width 0.20066)
		(layer "F.Cu")
		(net "M_A_CPU1_CLK_DP<0>")
	)
	(segment
		(start 84.54009 -250.320556)
		(end 84.075524 -250.320556)
		(width 0.088646)
		(layer "F.Cu")
		(net "M_A_CPU1_CLK_DP<0>")
	)
	(segment
		(start 85.640672 -248.797064)
		(end 85.665818 -248.890028)
		(width 0.088646)
		(layer "F.Cu")
		(net "M_A_CPU1_CLK_DP<0>")
	)
	(segment
		(start 59.382914 -258.493514)
		(end 59.382914 -259.278628)
		(width 0.20066)
		(layer "F.Cu")
		(net "M_A_CPU1_CLK_DP<0>")
	)
	(segment
		(start 85.891116 -249.342148)
		(end 85.890862 -249.342148)
		(width 0.088646)
		(layer "F.Cu")
		(net "M_A_CPU1_CLK_DP<0>")
	)
	(segment
		(start 85.194902 -249.977656)
		(end 84.949792 -249.977656)
		(width 0.088646)
		(layer "F.Cu")
		(net "M_A_CPU1_CLK_DP<0>")
	)
	(segment
		(start 79.293212 -254.625856)
		(end 72.847454 -254.625856)
		(width 0.20066)
		(layer "F.Cu")
		(net "M_A_CPU1_CLK_DP<0>")
	)
	(segment
		(start 72.847454 -254.625856)
		(end 60.016898 -257.61823)
		(width 0.20066)
		(layer "F.Cu")
		(net "M_A_CPU1_CLK_DP<0>")
	)
	(segment
		(start 83.97875 -250.38939)
		(end 83.316572 -250.38939)
		(width 0.20066)
		(layer "F.Cu")
		(net "M_A_CPU1_CLK_DP<0>")
	)
	(segment
		(start 84.075524 -250.320556)
		(end 84.00669 -250.38939)
		(width 0.088646)
		(layer "F.Cu")
		(net "M_A_CPU1_CLK_DP<0>")
	)
	(segment
		(start 59.504072 -258.20116)
		(end 59.382914 -258.493514)
		(width 0.20066)
		(layer "F.Cu")
		(net "M_A_CPU1_CLK_DP<0>")
	)
	(segment
		(start 81.414112 -252.504956)
		(end 79.293212 -254.625856)
		(width 0.20066)
		(layer "F.Cu")
		(net "M_A_CPU1_CLK_DP<0>")
	)
	(segment
		(start 81.843372 -251.86259)
		(end 81.414112 -252.504956)
		(width 0.20066)
		(layer "F.Cu")
		(net "M_A_CPU1_CLK_DP<0>")
	)
	(segment
		(start 60.016898 -257.61823)
		(end 59.553602 -258.081272)
		(width 0.20066)
		(layer "F.Cu")
		(net "M_A_CPU1_CLK_DP<0>")
	)
	(segment
		(start 58.693304 -259.968238)
		(end 58.297826 -259.968238)
		(width 0.20066)
		(layer "F.Cu")
		(net "M_A_CPU1_CLK_DP<0>")
	)
	(segment
		(start 58.049414 -260.21665)
		(end 57.503314 -260.21665)
		(width 0.20066)
		(layer "F.Cu")
		(net "M_A_CPU1_CLK_DP<0>")
	)
	(segment
		(start 85.891116 -249.327924)
		(end 85.891116 -249.342148)
		(width 0.088646)
		(layer "F.Cu")
		(net "M_A_CPU1_CLK_DP<0>")
	)
	(segment
		(start 84.835746 -250.0249)
		(end 84.54009 -250.320556)
		(width 0.088646)
		(layer "F.Cu")
		(net "M_A_CPU1_CLK_DP<0>")
	)
	(segment
		(start 59.553602 -258.081272)
		(end 59.504072 -258.20116)
		(width 0.20066)
		(layer "F.Cu")
		(net "M_A_CPU1_CLK_DP<0>")
	)
	(segment
		(start 85.583014 -249.867674)
		(end 85.513418 -249.902472)
		(width 0.088646)
		(layer "F.Cu")
		(net "M_A_CPU1_CLK_DP<0>")
	)
	(segment
		(start 85.795866 -248.528078)
		(end 85.640672 -248.797064)
		(width 0.088646)
		(layer "F.Cu")
		(net "M_A_CPU1_CLK_DP<0>")
	)
	(segment
		(start 59.382914 -259.278628)
		(end 58.693304 -259.968238)
		(width 0.20066)
		(layer "F.Cu")
		(net "M_A_CPU1_CLK_DP<0>")
	)
	(segment
		(start 84.00669 -250.38939)
		(end 83.97875 -250.38939)
		(width 0.088646)
		(layer "F.Cu")
		(net "M_A_CPU1_CLK_DP<0>")
	)
	(arc
		(start 85.682582 -248.903236)
		(mid 85.833351 -249.092736)
		(end 85.891116 -249.327924)
		(width 0.088646)
		(layer "F.Cu")
		(net "M_A_CPU1_CLK_DP<0>")
	)
	(arc
		(start 85.665818 -248.890028)
		(mid 85.674262 -248.896553)
		(end 85.682582 -248.903236)
		(width 0.088646)
		(layer "F.Cu")
		(net "M_A_CPU1_CLK_DP<0>")
	)
	(arc
		(start 85.513418 -249.902472)
		(mid 85.358537 -249.958611)
		(end 85.194902 -249.977656)
		(width 0.088646)
		(layer "F.Cu")
		(net "M_A_CPU1_CLK_DP<0>")
	)
	(arc
		(start 85.890862 -249.342148)
		(mid 85.808309 -249.646734)
		(end 85.583014 -249.867674)
		(width 0.088646)
		(layer "F.Cu")
		(net "M_A_CPU1_CLK_DP<0>")
	)
	(arc
		(start 84.949792 -249.977656)
		(mid 84.888069 -249.989933)
		(end 84.835746 -250.0249)
		(width 0.088646)
		(layer "F.Cu")
		(net "M_A_CPU1_CLK_DP<0>")
	)
	(segment
		(start 84.00669 -251.092716)
		(end 84.07527 -251.161296)
		(width 0.088646)
		(layer "F.Cu")
		(net "M_A_CPU1_CLK_DN<1>")
	)
	(segment
		(start 73.096882 -255.267206)
		(end 79.68996 -255.267206)
		(width 0.20066)
		(layer "F.Cu")
		(net "M_A_CPU1_CLK_DN<1>")
	)
	(segment
		(start 82.158078 -252.798834)
		(end 82.84591 -251.769626)
		(width 0.20066)
		(layer "F.Cu")
		(net "M_A_CPU1_CLK_DN<1>")
	)
	(segment
		(start 87.018114 -249.666506)
		(end 87.018876 -249.667014)
		(width 0.088646)
		(layer "F.Cu")
		(net "M_A_CPU1_CLK_DN<1>")
	)
	(segment
		(start 87.0077 -249.66041)
		(end 87.018114 -249.666506)
		(width 0.088646)
		(layer "F.Cu")
		(net "M_A_CPU1_CLK_DN<1>")
	)
	(segment
		(start 68.627244 -257.118866)
		(end 73.096882 -255.267206)
		(width 0.20066)
		(layer "F.Cu")
		(net "M_A_CPU1_CLK_DN<1>")
	)
	(segment
		(start 65.557146 -259.366766)
		(end 65.851532 -259.661152)
		(width 0.20066)
		(layer "F.Cu")
		(net "M_A_CPU1_CLK_DN<1>")
	)
	(segment
		(start 65.047114 -259.366766)
		(end 65.557146 -259.366766)
		(width 0.20066)
		(layer "F.Cu")
		(net "M_A_CPU1_CLK_DN<1>")
	)
	(segment
		(start 83.97875 -251.092716)
		(end 84.00669 -251.092716)
		(width 0.088646)
		(layer "F.Cu")
		(net "M_A_CPU1_CLK_DN<1>")
	)
	(segment
		(start 79.68996 -255.267206)
		(end 82.158078 -252.798834)
		(width 0.20066)
		(layer "F.Cu")
		(net "M_A_CPU1_CLK_DN<1>")
	)
	(segment
		(start 65.851532 -259.661152)
		(end 66.084958 -259.661152)
		(width 0.20066)
		(layer "F.Cu")
		(net "M_A_CPU1_CLK_DN<1>")
	)
	(segment
		(start 87.36457 -250.155964)
		(end 87.675466 -250.155964)
		(width 0.088646)
		(layer "F.Cu")
		(net "M_A_CPU1_CLK_DN<1>")
	)
	(segment
		(start 86.100158 -250.756928)
		(end 86.17077 -250.587256)
		(width 0.088646)
		(layer "F.Cu")
		(net "M_A_CPU1_CLK_DN<1>")
	)
	(segment
		(start 85.696044 -251.161296)
		(end 86.100158 -250.756928)
		(width 0.088646)
		(layer "F.Cu")
		(net "M_A_CPU1_CLK_DN<1>")
	)
	(segment
		(start 83.52282 -251.092716)
		(end 83.97875 -251.092716)
		(width 0.20066)
		(layer "F.Cu")
		(net "M_A_CPU1_CLK_DN<1>")
	)
	(segment
		(start 87.018876 -249.667014)
		(end 87.02421 -249.670062)
		(width 0.088646)
		(layer "F.Cu")
		(net "M_A_CPU1_CLK_DN<1>")
	)
	(segment
		(start 66.084958 -259.661152)
		(end 68.627244 -257.118866)
		(width 0.20066)
		(layer "F.Cu")
		(net "M_A_CPU1_CLK_DN<1>")
	)
	(segment
		(start 84.07527 -251.161296)
		(end 85.696044 -251.161296)
		(width 0.088646)
		(layer "F.Cu")
		(net "M_A_CPU1_CLK_DN<1>")
	)
	(segment
		(start 87.296752 -250.088146)
		(end 87.36457 -250.155964)
		(width 0.088646)
		(layer "F.Cu")
		(net "M_A_CPU1_CLK_DN<1>")
	)
	(segment
		(start 82.84591 -251.769626)
		(end 83.52282 -251.092716)
		(width 0.20066)
		(layer "F.Cu")
		(net "M_A_CPU1_CLK_DN<1>")
	)
	(segment
		(start 86.17077 -250.587256)
		(end 86.17077 -250.155964)
		(width 0.088646)
		(layer "F.Cu")
		(net "M_A_CPU1_CLK_DN<1>")
	)
	(arc
		(start 86.453218 -249.666506)
		(mid 86.729666 -249.590765)
		(end 87.0077 -249.66041)
		(width 0.088646)
		(layer "F.Cu")
		(net "M_A_CPU1_CLK_DN<1>")
	)
	(arc
		(start 87.293704 -250.067064)
		(mid 87.295328 -250.077591)
		(end 87.296752 -250.088146)
		(width 0.088646)
		(layer "F.Cu")
		(net "M_A_CPU1_CLK_DN<1>")
	)
	(arc
		(start 87.02421 -249.670062)
		(mid 87.203207 -249.838531)
		(end 87.293704 -250.067064)
		(width 0.088646)
		(layer "F.Cu")
		(net "M_A_CPU1_CLK_DN<1>")
	)
	(arc
		(start 86.439756 -249.674634)
		(mid 86.446458 -249.670522)
		(end 86.453218 -249.666506)
		(width 0.088646)
		(layer "F.Cu")
		(net "M_A_CPU1_CLK_DN<1>")
	)
	(arc
		(start 86.17077 -250.155964)
		(mid 86.242578 -249.880268)
		(end 86.439756 -249.674634)
		(width 0.088646)
		(layer "F.Cu")
		(net "M_A_CPU1_CLK_DN<1>")
	)
	(segment
		(start 85.493352 -249.699526)
		(end 85.428328 -249.732292)
		(width 0.088646)
		(layer "F.Cu")
		(net "M_A_CPU1_CLK_DN<0>")
	)
	(segment
		(start 84.461096 -250.13031)
		(end 84.07527 -250.13031)
		(width 0.088646)
		(layer "F.Cu")
		(net "M_A_CPU1_CLK_DN<0>")
	)
	(segment
		(start 61.129418 -256.89433)
		(end 61.036454 -257.043936)
		(width 0.20066)
		(layer "F.Cu")
		(net "M_A_CPU1_CLK_DN<0>")
	)
	(segment
		(start 61.036454 -257.043936)
		(end 59.85129 -257.320288)
		(width 0.20066)
		(layer "F.Cu")
		(net "M_A_CPU1_CLK_DN<0>")
	)
	(segment
		(start 85.700362 -249.342148)
		(end 85.700616 -249.342402)
		(width 0.088646)
		(layer "F.Cu")
		(net "M_A_CPU1_CLK_DN<0>")
	)
	(segment
		(start 58.315098 -259.640578)
		(end 58.041286 -259.366766)
		(width 0.20066)
		(layer "F.Cu")
		(net "M_A_CPU1_CLK_DN<0>")
	)
	(segment
		(start 83.97875 -250.06173)
		(end 83.180682 -250.06173)
		(width 0.20066)
		(layer "F.Cu")
		(net "M_A_CPU1_CLK_DN<0>")
	)
	(segment
		(start 61.86551 -256.850388)
		(end 61.715904 -256.757424)
		(width 0.20066)
		(layer "F.Cu")
		(net "M_A_CPU1_CLK_DN<0>")
	)
	(segment
		(start 63.95974 -256.23393)
		(end 63.866776 -256.383536)
		(width 0.20066)
		(layer "F.Cu")
		(net "M_A_CPU1_CLK_DN<0>")
	)
	(segment
		(start 61.715904 -256.757424)
		(end 61.129418 -256.89433)
		(width 0.20066)
		(layer "F.Cu")
		(net "M_A_CPU1_CLK_DN<0>")
	)
	(segment
		(start 62.544452 -256.56413)
		(end 62.451742 -256.713736)
		(width 0.20066)
		(layer "F.Cu")
		(net "M_A_CPU1_CLK_DN<0>")
	)
	(segment
		(start 64.546226 -256.097278)
		(end 63.95974 -256.23393)
		(width 0.20066)
		(layer "F.Cu")
		(net "M_A_CPU1_CLK_DN<0>")
	)
	(segment
		(start 79.157322 -254.298196)
		(end 72.809608 -254.298196)
		(width 0.20066)
		(layer "F.Cu")
		(net "M_A_CPU1_CLK_DN<0>")
	)
	(segment
		(start 85.195156 -249.78741)
		(end 84.949538 -249.78741)
		(width 0.088646)
		(layer "F.Cu")
		(net "M_A_CPU1_CLK_DN<0>")
	)
	(segment
		(start 59.85129 -257.320288)
		(end 59.275472 -257.895598)
		(width 0.20066)
		(layer "F.Cu")
		(net "M_A_CPU1_CLK_DN<0>")
	)
	(segment
		(start 64.695578 -256.190242)
		(end 64.546226 -256.097278)
		(width 0.20066)
		(layer "F.Cu")
		(net "M_A_CPU1_CLK_DN<0>")
	)
	(segment
		(start 59.275472 -257.895598)
		(end 59.149234 -258.20116)
		(width 0.20066)
		(layer "F.Cu")
		(net "M_A_CPU1_CLK_DN<0>")
	)
	(segment
		(start 84.00669 -250.06173)
		(end 83.97875 -250.06173)
		(width 0.088646)
		(layer "F.Cu")
		(net "M_A_CPU1_CLK_DN<0>")
	)
	(segment
		(start 63.131192 -256.427478)
		(end 62.544452 -256.56413)
		(width 0.20066)
		(layer "F.Cu")
		(net "M_A_CPU1_CLK_DN<0>")
	)
	(segment
		(start 66.696844 -255.723644)
		(end 66.110612 -255.860296)
		(width 0.20066)
		(layer "F.Cu")
		(net "M_A_CPU1_CLK_DN<0>")
	)
	(segment
		(start 59.149234 -258.20116)
		(end 59.055254 -258.428236)
		(width 0.20066)
		(layer "F.Cu")
		(net "M_A_CPU1_CLK_DN<0>")
	)
	(segment
		(start 58.557414 -259.640578)
		(end 58.315098 -259.640578)
		(width 0.20066)
		(layer "F.Cu")
		(net "M_A_CPU1_CLK_DN<0>")
	)
	(segment
		(start 72.809608 -254.298196)
		(end 67.525646 -255.53035)
		(width 0.20066)
		(layer "F.Cu")
		(net "M_A_CPU1_CLK_DN<0>")
	)
	(segment
		(start 65.28181 -256.05359)
		(end 64.695578 -256.190242)
		(width 0.20066)
		(layer "F.Cu")
		(net "M_A_CPU1_CLK_DN<0>")
	)
	(segment
		(start 85.325712 -249.342148)
		(end 85.480906 -249.073162)
		(width 0.088646)
		(layer "F.Cu")
		(net "M_A_CPU1_CLK_DN<0>")
	)
	(segment
		(start 66.110612 -255.860296)
		(end 65.96126 -255.767332)
		(width 0.20066)
		(layer "F.Cu")
		(net "M_A_CPU1_CLK_DN<0>")
	)
	(segment
		(start 83.180682 -250.06173)
		(end 81.58861 -251.653548)
		(width 0.20066)
		(layer "F.Cu")
		(net "M_A_CPU1_CLK_DN<0>")
	)
	(segment
		(start 63.866776 -256.383536)
		(end 63.280544 -256.520188)
		(width 0.20066)
		(layer "F.Cu")
		(net "M_A_CPU1_CLK_DN<0>")
	)
	(segment
		(start 62.451742 -256.713736)
		(end 61.86551 -256.850388)
		(width 0.20066)
		(layer "F.Cu")
		(net "M_A_CPU1_CLK_DN<0>")
	)
	(segment
		(start 63.280544 -256.520188)
		(end 63.131192 -256.427478)
		(width 0.20066)
		(layer "F.Cu")
		(net "M_A_CPU1_CLK_DN<0>")
	)
	(segment
		(start 59.055254 -258.428236)
		(end 59.055254 -259.142738)
		(width 0.20066)
		(layer "F.Cu")
		(net "M_A_CPU1_CLK_DN<0>")
	)
	(segment
		(start 84.701126 -249.89028)
		(end 84.461096 -250.13031)
		(width 0.088646)
		(layer "F.Cu")
		(net "M_A_CPU1_CLK_DN<0>")
	)
	(segment
		(start 67.525646 -255.53035)
		(end 67.376294 -255.437386)
		(width 0.20066)
		(layer "F.Cu")
		(net "M_A_CPU1_CLK_DN<0>")
	)
	(segment
		(start 65.374774 -255.903984)
		(end 65.28181 -256.05359)
		(width 0.20066)
		(layer "F.Cu")
		(net "M_A_CPU1_CLK_DN<0>")
	)
	(segment
		(start 66.789808 -255.574038)
		(end 66.696844 -255.723644)
		(width 0.20066)
		(layer "F.Cu")
		(net "M_A_CPU1_CLK_DN<0>")
	)
	(segment
		(start 84.07527 -250.13031)
		(end 84.00669 -250.06173)
		(width 0.088646)
		(layer "F.Cu")
		(net "M_A_CPU1_CLK_DN<0>")
	)
	(segment
		(start 58.041286 -259.366766)
		(end 57.503314 -259.366766)
		(width 0.20066)
		(layer "F.Cu")
		(net "M_A_CPU1_CLK_DN<0>")
	)
	(segment
		(start 65.96126 -255.767332)
		(end 65.374774 -255.903984)
		(width 0.20066)
		(layer "F.Cu")
		(net "M_A_CPU1_CLK_DN<0>")
	)
	(segment
		(start 67.376294 -255.437386)
		(end 66.789808 -255.574038)
		(width 0.20066)
		(layer "F.Cu")
		(net "M_A_CPU1_CLK_DN<0>")
	)
	(segment
		(start 59.055254 -259.142738)
		(end 58.557414 -259.640578)
		(width 0.20066)
		(layer "F.Cu")
		(net "M_A_CPU1_CLK_DN<0>")
	)
	(segment
		(start 81.58861 -251.653548)
		(end 81.15935 -252.295914)
		(width 0.20066)
		(layer "F.Cu")
		(net "M_A_CPU1_CLK_DN<0>")
	)
	(segment
		(start 85.480906 -249.073162)
		(end 85.561932 -249.051572)
		(width 0.088646)
		(layer "F.Cu")
		(net "M_A_CPU1_CLK_DN<0>")
	)
	(segment
		(start 81.15935 -252.295914)
		(end 79.157322 -254.298196)
		(width 0.20066)
		(layer "F.Cu")
		(net "M_A_CPU1_CLK_DN<0>")
	)
	(arc
		(start 85.561932 -249.051572)
		(mid 85.663953 -249.181234)
		(end 85.700362 -249.342148)
		(width 0.088646)
		(layer "F.Cu")
		(net "M_A_CPU1_CLK_DN<0>")
	)
	(arc
		(start 85.700616 -249.342402)
		(mid 85.644987 -249.548823)
		(end 85.493352 -249.699526)
		(width 0.088646)
		(layer "F.Cu")
		(net "M_A_CPU1_CLK_DN<0>")
	)
	(arc
		(start 84.949538 -249.78741)
		(mid 84.815133 -249.814203)
		(end 84.701126 -249.89028)
		(width 0.088646)
		(layer "F.Cu")
		(net "M_A_CPU1_CLK_DN<0>")
	)
	(arc
		(start 85.428328 -249.732292)
		(mid 85.314947 -249.773404)
		(end 85.195156 -249.78741)
		(width 0.088646)
		(layer "F.Cu")
		(net "M_A_CPU1_CLK_DN<0>")
	)
	(segment
		(start 56.22163 -269.141702)
		(end 55.760366 -269.141702)
		(width 0.20066)
		(layer "F.Cu")
		(net "M_A_CPU1_ALERT_N")
	)
	(segment
		(start 62.051946 -269.566644)
		(end 60.947046 -269.566644)
		(width 0.20066)
		(layer "F.Cu")
		(net "M_A_CPU1_ALERT_N")
	)
	(segment
		(start 54.007766 -269.566644)
		(end 53.403246 -269.566644)
		(width 0.20066)
		(layer "F.Cu")
		(net "M_A_CPU1_ALERT_N")
	)
	(segment
		(start 55.583328 -269.58417)
		(end 55.34914 -269.818358)
		(width 0.20066)
		(layer "F.Cu")
		(net "M_A_CPU1_ALERT_N")
	)
	(segment
		(start 60.947046 -269.566644)
		(end 59.266582 -269.566644)
		(width 0.20066)
		(layer "F.Cu")
		(net "M_A_CPU1_ALERT_N")
	)
	(segment
		(start 55.760366 -269.141702)
		(end 55.583328 -269.31874)
		(width 0.20066)
		(layer "F.Cu")
		(net "M_A_CPU1_ALERT_N")
	)
	(segment
		(start 58.84164 -269.141702)
		(end 58.704226 -269.141702)
		(width 0.20066)
		(layer "F.Cu")
		(net "M_A_CPU1_ALERT_N")
	)
	(segment
		(start 54.25948 -269.818358)
		(end 54.007766 -269.566644)
		(width 0.20066)
		(layer "F.Cu")
		(net "M_A_CPU1_ALERT_N")
	)
	(segment
		(start 56.686704 -269.141702)
		(end 56.22163 -269.141702)
		(width 0.101854)
		(layer "F.Cu")
		(net "M_A_CPU1_ALERT_N")
	)
	(segment
		(start 58.703972 -269.141702)
		(end 56.686704 -269.141702)
		(width 0.1016)
		(layer "F.Cu")
		(net "M_A_CPU1_ALERT_N")
	)
	(segment
		(start 101.412294 -255.011682)
		(end 101.412294 -255.547368)
		(width 0.20066)
		(layer "F.Cu")
		(net "M_A_CPU1_ALERT_N")
	)
	(segment
		(start 101.412294 -255.547368)
		(end 101.412548 -255.547622)
		(width 0.20066)
		(layer "F.Cu")
		(net "M_A_CPU1_ALERT_N")
	)
	(segment
		(start 55.34914 -269.818358)
		(end 54.25948 -269.818358)
		(width 0.20066)
		(layer "F.Cu")
		(net "M_A_CPU1_ALERT_N")
	)
	(segment
		(start 55.583328 -269.31874)
		(end 55.583328 -269.58417)
		(width 0.20066)
		(layer "F.Cu")
		(net "M_A_CPU1_ALERT_N")
	)
	(segment
		(start 58.704226 -269.141702)
		(end 58.703972 -269.141702)
		(width 0.101854)
		(layer "F.Cu")
		(net "M_A_CPU1_ALERT_N")
	)
	(segment
		(start 59.266582 -269.566644)
		(end 58.84164 -269.141702)
		(width 0.20066)
		(layer "F.Cu")
		(net "M_A_CPU1_ALERT_N")
	)
	(via
		(at 62.051946 -269.566644)
		(size 0.4572)
		(drill 0.2032)
		(layers "F.Cu" "B.Cu")
		(net "M_A_CPU1_ALERT_N")
	)
	(via
		(at 101.412548 -255.547622)
		(size 0.4572)
		(drill 0.2032)
		(layers "F.Cu" "B.Cu")
		(net "M_A_CPU1_ALERT_N")
	)
	(segment
		(start 94.60357 -260.02107)
		(end 94.598744 -260.023864)
		(width 0.18288)
		(layer "In4.Cu")
		(net "M_A_CPU1_ALERT_N")
	)
	(segment
		(start 93.189044 -260.023864)
		(end 93.175582 -260.01599)
		(width 0.18288)
		(layer "In4.Cu")
		(net "M_A_CPU1_ALERT_N")
	)
	(segment
		(start 101.412548 -255.547622)
		(end 100.707698 -255.95453)
		(width 0.18288)
		(layer "In4.Cu")
		(net "M_A_CPU1_ALERT_N")
	)
	(segment
		(start 100.707698 -255.95453)
		(end 100.702872 -255.957324)
		(width 0.18288)
		(layer "In4.Cu")
		(net "M_A_CPU1_ALERT_N")
	)
	(segment
		(start 63.728346 -268.57198)
		(end 62.733682 -269.566644)
		(width 0.18288)
		(layer "In4.Cu")
		(net "M_A_CPU1_ALERT_N")
	)
	(segment
		(start 89.429844 -260.023864)
		(end 89.416382 -260.01599)
		(width 0.18288)
		(layer "In4.Cu")
		(net "M_A_CPU1_ALERT_N")
	)
	(segment
		(start 69.995796 -263.169654)
		(end 64.59347 -268.57198)
		(width 0.18288)
		(layer "In4.Cu")
		(net "M_A_CPU1_ALERT_N")
	)
	(segment
		(start 91.779344 -260.023864)
		(end 91.769692 -260.029452)
		(width 0.18288)
		(layer "In4.Cu")
		(net "M_A_CPU1_ALERT_N")
	)
	(segment
		(start 62.733682 -269.566644)
		(end 62.051946 -269.566644)
		(width 0.18288)
		(layer "In4.Cu")
		(net "M_A_CPU1_ALERT_N")
	)
	(segment
		(start 97.888044 -258.395978)
		(end 97.878392 -258.39039)
		(width 0.18288)
		(layer "In4.Cu")
		(net "M_A_CPU1_ALERT_N")
	)
	(segment
		(start 99.302824 -258.393184)
		(end 99.297998 -258.395978)
		(width 0.18288)
		(layer "In4.Cu")
		(net "M_A_CPU1_ALERT_N")
	)
	(segment
		(start 96.948498 -258.395978)
		(end 96.938846 -258.39039)
		(width 0.18288)
		(layer "In4.Cu")
		(net "M_A_CPU1_ALERT_N")
	)
	(segment
		(start 100.002848 -257.165602)
		(end 100.002848 -257.175254)
		(width 0.18288)
		(layer "In4.Cu")
		(net "M_A_CPU1_ALERT_N")
	)
	(segment
		(start 99.781868 -257.57378)
		(end 99.767644 -257.582162)
		(width 0.18288)
		(layer "In4.Cu")
		(net "M_A_CPU1_ALERT_N")
	)
	(segment
		(start 95.082868 -259.201666)
		(end 95.068644 -259.210048)
		(width 0.18288)
		(layer "In4.Cu")
		(net "M_A_CPU1_ALERT_N")
	)
	(segment
		(start 96.008444 -258.395978)
		(end 95.994982 -258.388104)
		(width 0.18288)
		(layer "In4.Cu")
		(net "M_A_CPU1_ALERT_N")
	)
	(segment
		(start 98.828098 -258.396232)
		(end 98.828098 -258.395978)
		(width 0.18288)
		(layer "In4.Cu")
		(net "M_A_CPU1_ALERT_N")
	)
	(segment
		(start 95.303848 -258.802632)
		(end 95.303848 -258.80314)
		(width 0.18288)
		(layer "In4.Cu")
		(net "M_A_CPU1_ALERT_N")
	)
	(segment
		(start 99.297998 -258.395978)
		(end 99.29749 -258.396232)
		(width 0.18288)
		(layer "In4.Cu")
		(net "M_A_CPU1_ALERT_N")
	)
	(segment
		(start 100.251768 -256.759964)
		(end 100.237544 -256.768346)
		(width 0.18288)
		(layer "In4.Cu")
		(net "M_A_CPU1_ALERT_N")
	)
	(segment
		(start 94.128844 -260.023864)
		(end 94.115382 -260.01599)
		(width 0.18288)
		(layer "In4.Cu")
		(net "M_A_CPU1_ALERT_N")
	)
	(segment
		(start 91.309698 -260.023864)
		(end 91.300046 -260.018276)
		(width 0.18288)
		(layer "In4.Cu")
		(net "M_A_CPU1_ALERT_N")
	)
	(segment
		(start 64.59347 -268.57198)
		(end 63.728346 -268.57198)
		(width 0.18288)
		(layer "In4.Cu")
		(net "M_A_CPU1_ALERT_N")
	)
	(segment
		(start 95.068644 -259.210048)
		(end 95.063818 -259.212842)
		(width 0.18288)
		(layer "In4.Cu")
		(net "M_A_CPU1_ALERT_N")
	)
	(segment
		(start 78.796134 -259.5245)
		(end 78.363826 -259.70357)
		(width 0.18288)
		(layer "In4.Cu")
		(net "M_A_CPU1_ALERT_N")
	)
	(segment
		(start 84.681822 -259.25653)
		(end 84.482178 -259.456174)
		(width 0.18288)
		(layer "In4.Cu")
		(net "M_A_CPU1_ALERT_N")
	)
	(segment
		(start 78.363826 -259.70357)
		(end 69.995796 -263.169654)
		(width 0.18288)
		(layer "In4.Cu")
		(net "M_A_CPU1_ALERT_N")
	)
	(segment
		(start 88.490298 -260.023864)
		(end 88.490044 -260.023864)
		(width 0.18288)
		(layer "In4.Cu")
		(net "M_A_CPU1_ALERT_N")
	)
	(segment
		(start 90.369644 -260.023864)
		(end 90.356182 -260.01599)
		(width 0.18288)
		(layer "In4.Cu")
		(net "M_A_CPU1_ALERT_N")
	)
	(segment
		(start 98.828098 -258.395978)
		(end 98.818446 -258.39039)
		(width 0.18288)
		(layer "In4.Cu")
		(net "M_A_CPU1_ALERT_N")
	)
	(segment
		(start 84.317332 -259.5245)
		(end 78.796134 -259.5245)
		(width 0.18288)
		(layer "In4.Cu")
		(net "M_A_CPU1_ALERT_N")
	)
	(segment
		(start 88.02497 -259.212842)
		(end 88.020144 -259.210048)
		(width 0.18288)
		(layer "In4.Cu")
		(net "M_A_CPU1_ALERT_N")
	)
	(segment
		(start 99.532948 -257.974592)
		(end 99.532948 -257.98907)
		(width 0.18288)
		(layer "In4.Cu")
		(net "M_A_CPU1_ALERT_N")
	)
	(segment
		(start 88.490044 -260.023864)
		(end 88.485218 -260.02107)
		(width 0.18288)
		(layer "In4.Cu")
		(net "M_A_CPU1_ALERT_N")
	)
	(arc
		(start 85.200744 -259.210048)
		(mid 85.024787 -259.150678)
		(end 84.839556 -259.164074)
		(width 0.18288)
		(layer "In4.Cu")
		(net "M_A_CPU1_ALERT_N")
	)
	(arc
		(start 91.769692 -260.029452)
		(mid 91.538961 -260.086813)
		(end 91.309698 -260.023864)
		(width 0.18288)
		(layer "In4.Cu")
		(net "M_A_CPU1_ALERT_N")
	)
	(arc
		(start 99.767644 -257.582162)
		(mid 99.59934 -257.747902)
		(end 99.532948 -257.974592)
		(width 0.18288)
		(layer "In4.Cu")
		(net "M_A_CPU1_ALERT_N")
	)
	(arc
		(start 100.237544 -256.768346)
		(mid 100.068094 -256.936192)
		(end 100.002848 -257.165602)
		(width 0.18288)
		(layer "In4.Cu")
		(net "M_A_CPU1_ALERT_N")
	)
	(arc
		(start 86.610444 -259.210048)
		(mid 86.375494 -259.273008)
		(end 86.140544 -259.210048)
		(width 0.18288)
		(layer "In4.Cu")
		(net "M_A_CPU1_ALERT_N")
	)
	(arc
		(start 88.020144 -259.210048)
		(mid 87.785194 -259.147088)
		(end 87.550244 -259.210048)
		(width 0.18288)
		(layer "In4.Cu")
		(net "M_A_CPU1_ALERT_N")
	)
	(arc
		(start 97.418398 -258.395978)
		(mid 97.183448 -258.458938)
		(end 96.948498 -258.395978)
		(width 0.18288)
		(layer "In4.Cu")
		(net "M_A_CPU1_ALERT_N")
	)
	(arc
		(start 96.938846 -258.39039)
		(mid 96.707861 -258.332939)
		(end 96.478344 -258.395978)
		(width 0.18288)
		(layer "In4.Cu")
		(net "M_A_CPU1_ALERT_N")
	)
	(arc
		(start 94.598744 -260.023864)
		(mid 94.363794 -260.086824)
		(end 94.128844 -260.023864)
		(width 0.18288)
		(layer "In4.Cu")
		(net "M_A_CPU1_ALERT_N")
	)
	(arc
		(start 92.719144 -260.023864)
		(mid 92.484194 -260.086824)
		(end 92.249244 -260.023864)
		(width 0.18288)
		(layer "In4.Cu")
		(net "M_A_CPU1_ALERT_N")
	)
	(arc
		(start 100.702872 -255.957324)
		(mid 100.534316 -256.128918)
		(end 100.472748 -256.361438)
		(width 0.18288)
		(layer "In4.Cu")
		(net "M_A_CPU1_ALERT_N")
	)
	(arc
		(start 94.833694 -259.616956)
		(mid 94.772131 -259.849479)
		(end 94.60357 -260.02107)
		(width 0.18288)
		(layer "In4.Cu")
		(net "M_A_CPU1_ALERT_N")
	)
	(arc
		(start 90.839544 -260.023864)
		(mid 90.604594 -260.086824)
		(end 90.369644 -260.023864)
		(width 0.18288)
		(layer "In4.Cu")
		(net "M_A_CPU1_ALERT_N")
	)
	(arc
		(start 95.063818 -259.212842)
		(mid 94.895262 -259.384436)
		(end 94.833694 -259.616956)
		(width 0.18288)
		(layer "In4.Cu")
		(net "M_A_CPU1_ALERT_N")
	)
	(arc
		(start 85.670644 -259.210048)
		(mid 85.435694 -259.273008)
		(end 85.200744 -259.210048)
		(width 0.18288)
		(layer "In4.Cu")
		(net "M_A_CPU1_ALERT_N")
	)
	(arc
		(start 84.839556 -259.164074)
		(mid 84.754726 -259.200128)
		(end 84.681822 -259.25653)
		(width 0.18288)
		(layer "In4.Cu")
		(net "M_A_CPU1_ALERT_N")
	)
	(arc
		(start 95.303848 -258.80314)
		(mid 95.24491 -259.030992)
		(end 95.082868 -259.201666)
		(width 0.18288)
		(layer "In4.Cu")
		(net "M_A_CPU1_ALERT_N")
	)
	(arc
		(start 100.002848 -257.175254)
		(mid 99.94391 -257.403106)
		(end 99.781868 -257.57378)
		(width 0.18288)
		(layer "In4.Cu")
		(net "M_A_CPU1_ALERT_N")
	)
	(arc
		(start 93.175582 -260.01599)
		(mid 92.946329 -259.960746)
		(end 92.719144 -260.023864)
		(width 0.18288)
		(layer "In4.Cu")
		(net "M_A_CPU1_ALERT_N")
	)
	(arc
		(start 87.550244 -259.210048)
		(mid 87.315294 -259.273008)
		(end 87.080344 -259.210048)
		(width 0.18288)
		(layer "In4.Cu")
		(net "M_A_CPU1_ALERT_N")
	)
	(arc
		(start 93.658944 -260.023864)
		(mid 93.423994 -260.086824)
		(end 93.189044 -260.023864)
		(width 0.18288)
		(layer "In4.Cu")
		(net "M_A_CPU1_ALERT_N")
	)
	(arc
		(start 94.115382 -260.01599)
		(mid 93.886129 -259.960746)
		(end 93.658944 -260.023864)
		(width 0.18288)
		(layer "In4.Cu")
		(net "M_A_CPU1_ALERT_N")
	)
	(arc
		(start 89.416382 -260.01599)
		(mid 89.187129 -259.960746)
		(end 88.959944 -260.023864)
		(width 0.18288)
		(layer "In4.Cu")
		(net "M_A_CPU1_ALERT_N")
	)
	(arc
		(start 95.538544 -258.395978)
		(mid 95.366731 -258.567871)
		(end 95.303848 -258.802632)
		(width 0.18288)
		(layer "In4.Cu")
		(net "M_A_CPU1_ALERT_N")
	)
	(arc
		(start 96.478344 -258.395978)
		(mid 96.243394 -258.458938)
		(end 96.008444 -258.395978)
		(width 0.18288)
		(layer "In4.Cu")
		(net "M_A_CPU1_ALERT_N")
	)
	(arc
		(start 88.959944 -260.023864)
		(mid 88.725138 -260.086731)
		(end 88.490298 -260.023864)
		(width 0.18288)
		(layer "In4.Cu")
		(net "M_A_CPU1_ALERT_N")
	)
	(arc
		(start 88.255094 -259.616956)
		(mid 88.193531 -259.384433)
		(end 88.02497 -259.212842)
		(width 0.18288)
		(layer "In4.Cu")
		(net "M_A_CPU1_ALERT_N")
	)
	(arc
		(start 98.818446 -258.39039)
		(mid 98.587461 -258.332939)
		(end 98.357944 -258.395978)
		(width 0.18288)
		(layer "In4.Cu")
		(net "M_A_CPU1_ALERT_N")
	)
	(arc
		(start 92.249244 -260.023864)
		(mid 92.014294 -259.960904)
		(end 91.779344 -260.023864)
		(width 0.18288)
		(layer "In4.Cu")
		(net "M_A_CPU1_ALERT_N")
	)
	(arc
		(start 99.532948 -257.98907)
		(mid 99.471385 -258.221593)
		(end 99.302824 -258.393184)
		(width 0.18288)
		(layer "In4.Cu")
		(net "M_A_CPU1_ALERT_N")
	)
	(arc
		(start 97.878392 -258.39039)
		(mid 97.647661 -258.33306)
		(end 97.418398 -258.395978)
		(width 0.18288)
		(layer "In4.Cu")
		(net "M_A_CPU1_ALERT_N")
	)
	(arc
		(start 90.356182 -260.01599)
		(mid 90.126929 -259.960746)
		(end 89.899744 -260.023864)
		(width 0.18288)
		(layer "In4.Cu")
		(net "M_A_CPU1_ALERT_N")
	)
	(arc
		(start 100.472748 -256.361438)
		(mid 100.41381 -256.58929)
		(end 100.251768 -256.759964)
		(width 0.18288)
		(layer "In4.Cu")
		(net "M_A_CPU1_ALERT_N")
	)
	(arc
		(start 98.357944 -258.395978)
		(mid 98.122994 -258.458938)
		(end 97.888044 -258.395978)
		(width 0.18288)
		(layer "In4.Cu")
		(net "M_A_CPU1_ALERT_N")
	)
	(arc
		(start 99.29749 -258.396232)
		(mid 99.062794 -258.459099)
		(end 98.828098 -258.396232)
		(width 0.18288)
		(layer "In4.Cu")
		(net "M_A_CPU1_ALERT_N")
	)
	(arc
		(start 84.482178 -259.456174)
		(mid 84.40656 -259.506763)
		(end 84.317332 -259.5245)
		(width 0.18288)
		(layer "In4.Cu")
		(net "M_A_CPU1_ALERT_N")
	)
	(arc
		(start 86.140544 -259.210048)
		(mid 85.905594 -259.147088)
		(end 85.670644 -259.210048)
		(width 0.18288)
		(layer "In4.Cu")
		(net "M_A_CPU1_ALERT_N")
	)
	(arc
		(start 89.899744 -260.023864)
		(mid 89.664794 -260.086824)
		(end 89.429844 -260.023864)
		(width 0.18288)
		(layer "In4.Cu")
		(net "M_A_CPU1_ALERT_N")
	)
	(arc
		(start 95.994982 -258.388104)
		(mid 95.765729 -258.33289)
		(end 95.538544 -258.395978)
		(width 0.18288)
		(layer "In4.Cu")
		(net "M_A_CPU1_ALERT_N")
	)
	(arc
		(start 87.080344 -259.210048)
		(mid 86.845394 -259.147088)
		(end 86.610444 -259.210048)
		(width 0.18288)
		(layer "In4.Cu")
		(net "M_A_CPU1_ALERT_N")
	)
	(arc
		(start 91.300046 -260.018276)
		(mid 91.069061 -259.960793)
		(end 90.839544 -260.023864)
		(width 0.18288)
		(layer "In4.Cu")
		(net "M_A_CPU1_ALERT_N")
	)
	(arc
		(start 88.485218 -260.02107)
		(mid 88.316662 -259.849476)
		(end 88.255094 -259.616956)
		(width 0.18288)
		(layer "In4.Cu")
		(net "M_A_CPU1_ALERT_N")
	)
	(segment
		(start 350.18218 -247.714262)
		(end 350.181164 -247.713246)
		(width 0.20066)
		(layer "F.Cu")
		(net "M_A_CPU0_SB_RSP<1>")
	)
	(segment
		(start 309.992014 -243.216684)
		(end 308.887114 -243.216684)
		(width 0.20066)
		(layer "F.Cu")
		(net "M_A_CPU0_SB_RSP<1>")
	)
	(segment
		(start 350.181164 -247.713246)
		(end 350.181164 -247.179592)
		(width 0.20066)
		(layer "F.Cu")
		(net "M_A_CPU0_SB_RSP<1>")
	)
	(segment
		(start 350.181164 -247.179592)
		(end 350.182434 -247.178322)
		(width 0.20066)
		(layer "F.Cu")
		(net "M_A_CPU0_SB_RSP<1>")
	)
	(segment
		(start 329.77328 -247.94464)
		(end 328.177652 -246.349012)
		(width 0.18288)
		(layer "In6.Cu")
		(net "M_A_CPU0_SB_RSP<1>")
	)
	(segment
		(start 346.620592 -247.496584)
		(end 346.618306 -247.497854)
		(width 0.088646)
		(layer "In6.Cu")
		(net "M_A_CPU0_SB_RSP<1>")
	)
	(segment
		(start 340.986364 -247.494044)
		(end 340.971632 -247.50268)
		(width 0.088646)
		(layer "In6.Cu")
		(net "M_A_CPU0_SB_RSP<1>")
	)
	(segment
		(start 317.553848 -247.738646)
		(end 314.344812 -244.52961)
		(width 0.18288)
		(layer "In6.Cu")
		(net "M_A_CPU0_SB_RSP<1>")
	)
	(segment
		(start 347.737684 -247.162828)
		(end 347.737684 -247.178322)
		(width 0.088646)
		(layer "In6.Cu")
		(net "M_A_CPU0_SB_RSP<1>")
	)
	(segment
		(start 344.740992 -247.496584)
		(end 344.730578 -247.50268)
		(width 0.088646)
		(layer "In6.Cu")
		(net "M_A_CPU0_SB_RSP<1>")
	)
	(segment
		(start 348.585536 -246.688864)
		(end 348.575122 -246.682768)
		(width 0.088646)
		(layer "In6.Cu")
		(net "M_A_CPU0_SB_RSP<1>")
	)
	(segment
		(start 349.525082 -246.688864)
		(end 349.514668 -246.682768)
		(width 0.088646)
		(layer "In6.Cu")
		(net "M_A_CPU0_SB_RSP<1>")
	)
	(segment
		(start 311.30494 -244.52961)
		(end 309.992014 -243.216684)
		(width 0.18288)
		(layer "In6.Cu")
		(net "M_A_CPU0_SB_RSP<1>")
	)
	(segment
		(start 328.177652 -246.349012)
		(end 321.750944 -246.349012)
		(width 0.18288)
		(layer "In6.Cu")
		(net "M_A_CPU0_SB_RSP<1>")
	)
	(segment
		(start 346.235782 -247.50268)
		(end 346.225368 -247.496584)
		(width 0.088646)
		(layer "In6.Cu")
		(net "M_A_CPU0_SB_RSP<1>")
	)
	(segment
		(start 344.356182 -247.50268)
		(end 344.345768 -247.496584)
		(width 0.088646)
		(layer "In6.Cu")
		(net "M_A_CPU0_SB_RSP<1>")
	)
	(segment
		(start 341.926164 -247.494044)
		(end 341.911432 -247.50268)
		(width 0.088646)
		(layer "In6.Cu")
		(net "M_A_CPU0_SB_RSP<1>")
	)
	(segment
		(start 350.182434 -247.178322)
		(end 350.02597 -247.44934)
		(width 0.088646)
		(layer "In6.Cu")
		(net "M_A_CPU0_SB_RSP<1>")
	)
	(segment
		(start 332.396338 -247.592342)
		(end 332.04404 -247.94464)
		(width 0.088646)
		(layer "In6.Cu")
		(net "M_A_CPU0_SB_RSP<1>")
	)
	(segment
		(start 346.618306 -247.497854)
		(end 346.610178 -247.50268)
		(width 0.088646)
		(layer "In6.Cu")
		(net "M_A_CPU0_SB_RSP<1>")
	)
	(segment
		(start 349.531178 -246.69242)
		(end 349.525082 -246.688864)
		(width 0.088646)
		(layer "In6.Cu")
		(net "M_A_CPU0_SB_RSP<1>")
	)
	(segment
		(start 350.02597 -247.44934)
		(end 349.947738 -247.470168)
		(width 0.088646)
		(layer "In6.Cu")
		(net "M_A_CPU0_SB_RSP<1>")
	)
	(segment
		(start 332.04404 -247.94464)
		(end 331.460602 -247.94464)
		(width 0.088646)
		(layer "In6.Cu")
		(net "M_A_CPU0_SB_RSP<1>")
	)
	(segment
		(start 331.460602 -247.94464)
		(end 329.77328 -247.94464)
		(width 0.18288)
		(layer "In6.Cu")
		(net "M_A_CPU0_SB_RSP<1>")
	)
	(segment
		(start 347.559122 -247.4976)
		(end 347.550232 -247.50268)
		(width 0.088646)
		(layer "In6.Cu")
		(net "M_A_CPU0_SB_RSP<1>")
	)
	(segment
		(start 337.777582 -247.50268)
		(end 337.767168 -247.496584)
		(width 0.088646)
		(layer "In6.Cu")
		(net "M_A_CPU0_SB_RSP<1>")
	)
	(segment
		(start 336.287364 -247.494044)
		(end 336.272632 -247.50268)
		(width 0.088646)
		(layer "In6.Cu")
		(net "M_A_CPU0_SB_RSP<1>")
	)
	(segment
		(start 314.344812 -244.52961)
		(end 311.30494 -244.52961)
		(width 0.18288)
		(layer "In6.Cu")
		(net "M_A_CPU0_SB_RSP<1>")
	)
	(segment
		(start 339.657182 -247.50268)
		(end 339.646768 -247.496584)
		(width 0.088646)
		(layer "In6.Cu")
		(net "M_A_CPU0_SB_RSP<1>")
	)
	(segment
		(start 321.750944 -246.349012)
		(end 320.36131 -247.738646)
		(width 0.18288)
		(layer "In6.Cu")
		(net "M_A_CPU0_SB_RSP<1>")
	)
	(segment
		(start 320.36131 -247.738646)
		(end 317.553848 -247.738646)
		(width 0.18288)
		(layer "In6.Cu")
		(net "M_A_CPU0_SB_RSP<1>")
	)
	(segment
		(start 340.041992 -247.496584)
		(end 340.031578 -247.50268)
		(width 0.088646)
		(layer "In6.Cu")
		(net "M_A_CPU0_SB_RSP<1>")
	)
	(segment
		(start 342.865964 -247.494044)
		(end 342.851232 -247.50268)
		(width 0.088646)
		(layer "In6.Cu")
		(net "M_A_CPU0_SB_RSP<1>")
	)
	(segment
		(start 338.162392 -247.496584)
		(end 338.151978 -247.50268)
		(width 0.088646)
		(layer "In6.Cu")
		(net "M_A_CPU0_SB_RSP<1>")
	)
	(arc
		(start 349.514668 -246.682768)
		(mid 349.23649 -246.613045)
		(end 348.959932 -246.688864)
		(width 0.088646)
		(layer "In6.Cu")
		(net "M_A_CPU0_SB_RSP<1>")
	)
	(arc
		(start 344.345768 -247.496584)
		(mid 344.06759 -247.426861)
		(end 343.791032 -247.50268)
		(width 0.088646)
		(layer "In6.Cu")
		(net "M_A_CPU0_SB_RSP<1>")
	)
	(arc
		(start 343.416636 -247.50268)
		(mid 343.142437 -247.426845)
		(end 342.865964 -247.494044)
		(width 0.088646)
		(layer "In6.Cu")
		(net "M_A_CPU0_SB_RSP<1>")
	)
	(arc
		(start 340.597236 -247.50268)
		(mid 340.320423 -247.42681)
		(end 340.041992 -247.496584)
		(width 0.088646)
		(layer "In6.Cu")
		(net "M_A_CPU0_SB_RSP<1>")
	)
	(arc
		(start 339.646768 -247.496584)
		(mid 339.36859 -247.426861)
		(end 339.092032 -247.50268)
		(width 0.088646)
		(layer "In6.Cu")
		(net "M_A_CPU0_SB_RSP<1>")
	)
	(arc
		(start 348.575122 -246.682768)
		(mid 348.29669 -246.612922)
		(end 348.019878 -246.688864)
		(width 0.088646)
		(layer "In6.Cu")
		(net "M_A_CPU0_SB_RSP<1>")
	)
	(arc
		(start 333.453232 -247.50268)
		(mid 333.266034 -247.552823)
		(end 333.078836 -247.50268)
		(width 0.088646)
		(layer "In6.Cu")
		(net "M_A_CPU0_SB_RSP<1>")
	)
	(arc
		(start 342.476836 -247.50268)
		(mid 342.202637 -247.426845)
		(end 341.926164 -247.494044)
		(width 0.088646)
		(layer "In6.Cu")
		(net "M_A_CPU0_SB_RSP<1>")
	)
	(arc
		(start 336.838036 -247.50268)
		(mid 336.563837 -247.426845)
		(end 336.287364 -247.494044)
		(width 0.088646)
		(layer "In6.Cu")
		(net "M_A_CPU0_SB_RSP<1>")
	)
	(arc
		(start 345.296236 -247.50268)
		(mid 345.019423 -247.42681)
		(end 344.740992 -247.496584)
		(width 0.088646)
		(layer "In6.Cu")
		(net "M_A_CPU0_SB_RSP<1>")
	)
	(arc
		(start 337.767168 -247.496584)
		(mid 337.48899 -247.426861)
		(end 337.212432 -247.50268)
		(width 0.088646)
		(layer "In6.Cu")
		(net "M_A_CPU0_SB_RSP<1>")
	)
	(arc
		(start 342.851232 -247.50268)
		(mid 342.664034 -247.552823)
		(end 342.476836 -247.50268)
		(width 0.088646)
		(layer "In6.Cu")
		(net "M_A_CPU0_SB_RSP<1>")
	)
	(arc
		(start 338.717636 -247.50268)
		(mid 338.440823 -247.42681)
		(end 338.162392 -247.496584)
		(width 0.088646)
		(layer "In6.Cu")
		(net "M_A_CPU0_SB_RSP<1>")
	)
	(arc
		(start 336.272632 -247.50268)
		(mid 336.085434 -247.552823)
		(end 335.898236 -247.50268)
		(width 0.088646)
		(layer "In6.Cu")
		(net "M_A_CPU0_SB_RSP<1>")
	)
	(arc
		(start 334.958436 -247.50268)
		(mid 334.675734 -247.426904)
		(end 334.393032 -247.50268)
		(width 0.088646)
		(layer "In6.Cu")
		(net "M_A_CPU0_SB_RSP<1>")
	)
	(arc
		(start 348.019878 -246.688864)
		(mid 347.817055 -246.889095)
		(end 347.737684 -247.162828)
		(width 0.088646)
		(layer "In6.Cu")
		(net "M_A_CPU0_SB_RSP<1>")
	)
	(arc
		(start 334.018636 -247.50268)
		(mid 333.735934 -247.426904)
		(end 333.453232 -247.50268)
		(width 0.088646)
		(layer "In6.Cu")
		(net "M_A_CPU0_SB_RSP<1>")
	)
	(arc
		(start 346.225368 -247.496584)
		(mid 345.94719 -247.426861)
		(end 345.670632 -247.50268)
		(width 0.088646)
		(layer "In6.Cu")
		(net "M_A_CPU0_SB_RSP<1>")
	)
	(arc
		(start 346.610178 -247.50268)
		(mid 346.42298 -247.552823)
		(end 346.235782 -247.50268)
		(width 0.088646)
		(layer "In6.Cu")
		(net "M_A_CPU0_SB_RSP<1>")
	)
	(arc
		(start 347.737684 -247.178322)
		(mid 347.690005 -247.361222)
		(end 347.559122 -247.4976)
		(width 0.088646)
		(layer "In6.Cu")
		(net "M_A_CPU0_SB_RSP<1>")
	)
	(arc
		(start 335.332832 -247.50268)
		(mid 335.145634 -247.552823)
		(end 334.958436 -247.50268)
		(width 0.088646)
		(layer "In6.Cu")
		(net "M_A_CPU0_SB_RSP<1>")
	)
	(arc
		(start 349.807784 -247.178322)
		(mid 349.733793 -246.898756)
		(end 349.531178 -246.69242)
		(width 0.088646)
		(layer "In6.Cu")
		(net "M_A_CPU0_SB_RSP<1>")
	)
	(arc
		(start 340.031578 -247.50268)
		(mid 339.84438 -247.552823)
		(end 339.657182 -247.50268)
		(width 0.088646)
		(layer "In6.Cu")
		(net "M_A_CPU0_SB_RSP<1>")
	)
	(arc
		(start 341.911432 -247.50268)
		(mid 341.724234 -247.552823)
		(end 341.537036 -247.50268)
		(width 0.088646)
		(layer "In6.Cu")
		(net "M_A_CPU0_SB_RSP<1>")
	)
	(arc
		(start 338.151978 -247.50268)
		(mid 337.96478 -247.552823)
		(end 337.777582 -247.50268)
		(width 0.088646)
		(layer "In6.Cu")
		(net "M_A_CPU0_SB_RSP<1>")
	)
	(arc
		(start 349.947738 -247.470168)
		(mid 349.844593 -247.340143)
		(end 349.807784 -247.178322)
		(width 0.088646)
		(layer "In6.Cu")
		(net "M_A_CPU0_SB_RSP<1>")
	)
	(arc
		(start 334.393032 -247.50268)
		(mid 334.205834 -247.552823)
		(end 334.018636 -247.50268)
		(width 0.088646)
		(layer "In6.Cu")
		(net "M_A_CPU0_SB_RSP<1>")
	)
	(arc
		(start 333.078836 -247.50268)
		(mid 332.796134 -247.426904)
		(end 332.513432 -247.50268)
		(width 0.088646)
		(layer "In6.Cu")
		(net "M_A_CPU0_SB_RSP<1>")
	)
	(arc
		(start 332.513432 -247.50268)
		(mid 332.451954 -247.543682)
		(end 332.396338 -247.592342)
		(width 0.088646)
		(layer "In6.Cu")
		(net "M_A_CPU0_SB_RSP<1>")
	)
	(arc
		(start 335.898236 -247.50268)
		(mid 335.615534 -247.426904)
		(end 335.332832 -247.50268)
		(width 0.088646)
		(layer "In6.Cu")
		(net "M_A_CPU0_SB_RSP<1>")
	)
	(arc
		(start 341.537036 -247.50268)
		(mid 341.262837 -247.426845)
		(end 340.986364 -247.494044)
		(width 0.088646)
		(layer "In6.Cu")
		(net "M_A_CPU0_SB_RSP<1>")
	)
	(arc
		(start 339.092032 -247.50268)
		(mid 338.904834 -247.552823)
		(end 338.717636 -247.50268)
		(width 0.088646)
		(layer "In6.Cu")
		(net "M_A_CPU0_SB_RSP<1>")
	)
	(arc
		(start 344.730578 -247.50268)
		(mid 344.54338 -247.552823)
		(end 344.356182 -247.50268)
		(width 0.088646)
		(layer "In6.Cu")
		(net "M_A_CPU0_SB_RSP<1>")
	)
	(arc
		(start 337.212432 -247.50268)
		(mid 337.025234 -247.552823)
		(end 336.838036 -247.50268)
		(width 0.088646)
		(layer "In6.Cu")
		(net "M_A_CPU0_SB_RSP<1>")
	)
	(arc
		(start 345.670632 -247.50268)
		(mid 345.483434 -247.552823)
		(end 345.296236 -247.50268)
		(width 0.088646)
		(layer "In6.Cu")
		(net "M_A_CPU0_SB_RSP<1>")
	)
	(arc
		(start 340.971632 -247.50268)
		(mid 340.784434 -247.552823)
		(end 340.597236 -247.50268)
		(width 0.088646)
		(layer "In6.Cu")
		(net "M_A_CPU0_SB_RSP<1>")
	)
	(arc
		(start 348.959932 -246.688864)
		(mid 348.772734 -246.739007)
		(end 348.585536 -246.688864)
		(width 0.088646)
		(layer "In6.Cu")
		(net "M_A_CPU0_SB_RSP<1>")
	)
	(arc
		(start 343.791032 -247.50268)
		(mid 343.603834 -247.552823)
		(end 343.416636 -247.50268)
		(width 0.088646)
		(layer "In6.Cu")
		(net "M_A_CPU0_SB_RSP<1>")
	)
	(arc
		(start 347.550232 -247.50268)
		(mid 347.363034 -247.552823)
		(end 347.175836 -247.50268)
		(width 0.088646)
		(layer "In6.Cu")
		(net "M_A_CPU0_SB_RSP<1>")
	)
	(arc
		(start 347.175836 -247.50268)
		(mid 346.899023 -247.42681)
		(end 346.620592 -247.496584)
		(width 0.088646)
		(layer "In6.Cu")
		(net "M_A_CPU0_SB_RSP<1>")
	)
	(segment
		(start 302.448214 -243.216684)
		(end 301.343314 -243.216684)
		(width 0.20066)
		(layer "F.Cu")
		(net "M_A_CPU0_SB_RSP<0>")
	)
	(segment
		(start 350.18218 -249.342148)
		(end 350.182434 -249.341894)
		(width 0.20066)
		(layer "F.Cu")
		(net "M_A_CPU0_SB_RSP<0>")
	)
	(segment
		(start 350.182434 -249.341894)
		(end 350.182434 -248.806208)
		(width 0.20066)
		(layer "F.Cu")
		(net "M_A_CPU0_SB_RSP<0>")
	)
	(segment
		(start 302.209708 -244.49151)
		(end 301.947834 -244.229636)
		(width 0.18288)
		(layer "In6.Cu")
		(net "M_A_CPU0_SB_RSP<0>")
	)
	(segment
		(start 348.500446 -248.487946)
		(end 348.490032 -248.48185)
		(width 0.088646)
		(layer "In6.Cu")
		(net "M_A_CPU0_SB_RSP<0>")
	)
	(segment
		(start 306.73548 -245.34495)
		(end 304.15611 -245.074948)
		(width 0.18288)
		(layer "In6.Cu")
		(net "M_A_CPU0_SB_RSP<0>")
	)
	(segment
		(start 302.781208 -244.52453)
		(end 302.71085 -244.490748)
		(width 0.18288)
		(layer "In6.Cu")
		(net "M_A_CPU0_SB_RSP<0>")
	)
	(segment
		(start 307.911754 -246.028972)
		(end 307.099716 -245.495826)
		(width 0.18288)
		(layer "In6.Cu")
		(net "M_A_CPU0_SB_RSP<0>")
	)
	(segment
		(start 336.287364 -248.490486)
		(end 336.272632 -248.48185)
		(width 0.088646)
		(layer "In6.Cu")
		(net "M_A_CPU0_SB_RSP<0>")
	)
	(segment
		(start 320.520314 -249.69216)
		(end 316.96279 -249.69216)
		(width 0.18288)
		(layer "In6.Cu")
		(net "M_A_CPU0_SB_RSP<0>")
	)
	(segment
		(start 346.625164 -248.490486)
		(end 346.618306 -248.486422)
		(width 0.088646)
		(layer "In6.Cu")
		(net "M_A_CPU0_SB_RSP<0>")
	)
	(segment
		(start 344.745564 -248.490486)
		(end 344.730832 -248.48185)
		(width 0.088646)
		(layer "In6.Cu")
		(net "M_A_CPU0_SB_RSP<0>")
	)
	(segment
		(start 334.494378 -249.29211)
		(end 334.488282 -249.295666)
		(width 0.088646)
		(layer "In6.Cu")
		(net "M_A_CPU0_SB_RSP<0>")
	)
	(segment
		(start 307.099716 -245.495826)
		(end 306.73548 -245.34495)
		(width 0.18288)
		(layer "In6.Cu")
		(net "M_A_CPU0_SB_RSP<0>")
	)
	(segment
		(start 316.96279 -249.69216)
		(end 314.311284 -247.040654)
		(width 0.18288)
		(layer "In6.Cu")
		(net "M_A_CPU0_SB_RSP<0>")
	)
	(segment
		(start 334.958436 -248.48185)
		(end 334.949546 -248.48693)
		(width 0.088646)
		(layer "In6.Cu")
		(net "M_A_CPU0_SB_RSP<0>")
	)
	(segment
		(start 302.710088 -244.49151)
		(end 302.209708 -244.49151)
		(width 0.18288)
		(layer "In6.Cu")
		(net "M_A_CPU0_SB_RSP<0>")
	)
	(segment
		(start 309.671212 -247.040654)
		(end 309.077614 -246.794782)
		(width 0.18288)
		(layer "In6.Cu")
		(net "M_A_CPU0_SB_RSP<0>")
	)
	(segment
		(start 341.921846 -248.487946)
		(end 341.911432 -248.48185)
		(width 0.088646)
		(layer "In6.Cu")
		(net "M_A_CPU0_SB_RSP<0>")
	)
	(segment
		(start 334.488282 -249.295666)
		(end 334.47355 -249.304302)
		(width 0.088646)
		(layer "In6.Cu")
		(net "M_A_CPU0_SB_RSP<0>")
	)
	(segment
		(start 347.564964 -248.490486)
		(end 347.550232 -248.48185)
		(width 0.088646)
		(layer "In6.Cu")
		(net "M_A_CPU0_SB_RSP<0>")
	)
	(segment
		(start 302.71085 -244.490748)
		(end 302.710088 -244.49151)
		(width 0.18288)
		(layer "In6.Cu")
		(net "M_A_CPU0_SB_RSP<0>")
	)
	(segment
		(start 301.947834 -244.229636)
		(end 301.947834 -243.717064)
		(width 0.18288)
		(layer "In6.Cu")
		(net "M_A_CPU0_SB_RSP<0>")
	)
	(segment
		(start 346.618306 -248.486422)
		(end 346.610432 -248.48185)
		(width 0.088646)
		(layer "In6.Cu")
		(net "M_A_CPU0_SB_RSP<0>")
	)
	(segment
		(start 314.311284 -247.040654)
		(end 309.671212 -247.040654)
		(width 0.18288)
		(layer "In6.Cu")
		(net "M_A_CPU0_SB_RSP<0>")
	)
	(segment
		(start 340.046564 -248.490486)
		(end 340.031832 -248.48185)
		(width 0.088646)
		(layer "In6.Cu")
		(net "M_A_CPU0_SB_RSP<0>")
	)
	(segment
		(start 330.313792 -249.924824)
		(end 327.764394 -247.375426)
		(width 0.18288)
		(layer "In6.Cu")
		(net "M_A_CPU0_SB_RSP<0>")
	)
	(segment
		(start 304.15611 -245.074948)
		(end 303.361598 -244.802914)
		(width 0.18288)
		(layer "In6.Cu")
		(net "M_A_CPU0_SB_RSP<0>")
	)
	(segment
		(start 338.166964 -248.490486)
		(end 338.152232 -248.48185)
		(width 0.088646)
		(layer "In6.Cu")
		(net "M_A_CPU0_SB_RSP<0>")
	)
	(segment
		(start 333.470758 -249.355102)
		(end 332.901036 -249.924824)
		(width 0.088646)
		(layer "In6.Cu")
		(net "M_A_CPU0_SB_RSP<0>")
	)
	(segment
		(start 309.077614 -246.794782)
		(end 307.911754 -246.028972)
		(width 0.18288)
		(layer "In6.Cu")
		(net "M_A_CPU0_SB_RSP<0>")
	)
	(segment
		(start 350.182434 -248.806208)
		(end 349.509334 -248.52757)
		(width 0.088646)
		(layer "In6.Cu")
		(net "M_A_CPU0_SB_RSP<0>")
	)
	(segment
		(start 331.460602 -249.924824)
		(end 330.313792 -249.924824)
		(width 0.18288)
		(layer "In6.Cu")
		(net "M_A_CPU0_SB_RSP<0>")
	)
	(segment
		(start 349.509334 -248.52757)
		(end 349.508826 -248.52757)
		(width 0.088646)
		(layer "In6.Cu")
		(net "M_A_CPU0_SB_RSP<0>")
	)
	(segment
		(start 303.361598 -244.802914)
		(end 302.781208 -244.52453)
		(width 0.18288)
		(layer "In6.Cu")
		(net "M_A_CPU0_SB_RSP<0>")
	)
	(segment
		(start 349.508826 -248.52757)
		(end 349.429578 -248.48185)
		(width 0.088646)
		(layer "In6.Cu")
		(net "M_A_CPU0_SB_RSP<0>")
	)
	(segment
		(start 332.901036 -249.924824)
		(end 331.460602 -249.924824)
		(width 0.088646)
		(layer "In6.Cu")
		(net "M_A_CPU0_SB_RSP<0>")
	)
	(segment
		(start 340.986364 -248.490486)
		(end 340.971632 -248.48185)
		(width 0.088646)
		(layer "In6.Cu")
		(net "M_A_CPU0_SB_RSP<0>")
	)
	(segment
		(start 342.861392 -248.487946)
		(end 342.850978 -248.48185)
		(width 0.088646)
		(layer "In6.Cu")
		(net "M_A_CPU0_SB_RSP<0>")
	)
	(segment
		(start 327.764394 -247.375426)
		(end 322.837048 -247.375426)
		(width 0.18288)
		(layer "In6.Cu")
		(net "M_A_CPU0_SB_RSP<0>")
	)
	(segment
		(start 322.837048 -247.375426)
		(end 320.520314 -249.69216)
		(width 0.18288)
		(layer "In6.Cu")
		(net "M_A_CPU0_SB_RSP<0>")
	)
	(segment
		(start 301.947834 -243.717064)
		(end 302.448214 -243.216684)
		(width 0.18288)
		(layer "In6.Cu")
		(net "M_A_CPU0_SB_RSP<0>")
	)
	(arc
		(start 337.212432 -248.48185)
		(mid 337.025234 -248.431707)
		(end 336.838036 -248.48185)
		(width 0.088646)
		(layer "In6.Cu")
		(net "M_A_CPU0_SB_RSP<0>")
	)
	(arc
		(start 342.850978 -248.48185)
		(mid 342.66378 -248.431707)
		(end 342.476582 -248.48185)
		(width 0.088646)
		(layer "In6.Cu")
		(net "M_A_CPU0_SB_RSP<0>")
	)
	(arc
		(start 339.092032 -248.48185)
		(mid 338.904834 -248.431707)
		(end 338.717636 -248.48185)
		(width 0.088646)
		(layer "In6.Cu")
		(net "M_A_CPU0_SB_RSP<0>")
	)
	(arc
		(start 347.175836 -248.48185)
		(mid 346.901607 -248.557775)
		(end 346.625164 -248.490486)
		(width 0.088646)
		(layer "In6.Cu")
		(net "M_A_CPU0_SB_RSP<0>")
	)
	(arc
		(start 338.152232 -248.48185)
		(mid 337.965034 -248.431707)
		(end 337.777836 -248.48185)
		(width 0.088646)
		(layer "In6.Cu")
		(net "M_A_CPU0_SB_RSP<0>")
	)
	(arc
		(start 339.657436 -248.48185)
		(mid 339.374734 -248.557592)
		(end 339.092032 -248.48185)
		(width 0.088646)
		(layer "In6.Cu")
		(net "M_A_CPU0_SB_RSP<0>")
	)
	(arc
		(start 333.922878 -249.295666)
		(mid 333.73568 -249.245523)
		(end 333.548482 -249.295666)
		(width 0.088646)
		(layer "In6.Cu")
		(net "M_A_CPU0_SB_RSP<0>")
	)
	(arc
		(start 334.47355 -249.304302)
		(mid 334.197075 -249.371622)
		(end 333.922878 -249.295666)
		(width 0.088646)
		(layer "In6.Cu")
		(net "M_A_CPU0_SB_RSP<0>")
	)
	(arc
		(start 335.332832 -248.48185)
		(mid 335.145634 -248.431707)
		(end 334.958436 -248.48185)
		(width 0.088646)
		(layer "In6.Cu")
		(net "M_A_CPU0_SB_RSP<0>")
	)
	(arc
		(start 334.770984 -248.806208)
		(mid 334.696993 -249.085774)
		(end 334.494378 -249.29211)
		(width 0.088646)
		(layer "In6.Cu")
		(net "M_A_CPU0_SB_RSP<0>")
	)
	(arc
		(start 341.911432 -248.48185)
		(mid 341.724234 -248.431707)
		(end 341.537036 -248.48185)
		(width 0.088646)
		(layer "In6.Cu")
		(net "M_A_CPU0_SB_RSP<0>")
	)
	(arc
		(start 348.115636 -248.48185)
		(mid 347.841407 -248.557775)
		(end 347.564964 -248.490486)
		(width 0.088646)
		(layer "In6.Cu")
		(net "M_A_CPU0_SB_RSP<0>")
	)
	(arc
		(start 346.236036 -248.48185)
		(mid 345.953334 -248.557592)
		(end 345.670632 -248.48185)
		(width 0.088646)
		(layer "In6.Cu")
		(net "M_A_CPU0_SB_RSP<0>")
	)
	(arc
		(start 337.777836 -248.48185)
		(mid 337.495134 -248.557592)
		(end 337.212432 -248.48185)
		(width 0.088646)
		(layer "In6.Cu")
		(net "M_A_CPU0_SB_RSP<0>")
	)
	(arc
		(start 333.548482 -249.295666)
		(mid 333.507673 -249.322838)
		(end 333.470758 -249.355102)
		(width 0.088646)
		(layer "In6.Cu")
		(net "M_A_CPU0_SB_RSP<0>")
	)
	(arc
		(start 334.949546 -248.48693)
		(mid 334.818632 -248.62329)
		(end 334.770984 -248.806208)
		(width 0.088646)
		(layer "In6.Cu")
		(net "M_A_CPU0_SB_RSP<0>")
	)
	(arc
		(start 343.791032 -248.48185)
		(mid 343.603834 -248.431707)
		(end 343.416636 -248.48185)
		(width 0.088646)
		(layer "In6.Cu")
		(net "M_A_CPU0_SB_RSP<0>")
	)
	(arc
		(start 345.296236 -248.48185)
		(mid 345.022007 -248.557775)
		(end 344.745564 -248.490486)
		(width 0.088646)
		(layer "In6.Cu")
		(net "M_A_CPU0_SB_RSP<0>")
	)
	(arc
		(start 340.971632 -248.48185)
		(mid 340.784434 -248.431707)
		(end 340.597236 -248.48185)
		(width 0.088646)
		(layer "In6.Cu")
		(net "M_A_CPU0_SB_RSP<0>")
	)
	(arc
		(start 348.490032 -248.48185)
		(mid 348.302834 -248.431707)
		(end 348.115636 -248.48185)
		(width 0.088646)
		(layer "In6.Cu")
		(net "M_A_CPU0_SB_RSP<0>")
	)
	(arc
		(start 338.717636 -248.48185)
		(mid 338.443407 -248.557775)
		(end 338.166964 -248.490486)
		(width 0.088646)
		(layer "In6.Cu")
		(net "M_A_CPU0_SB_RSP<0>")
	)
	(arc
		(start 343.416636 -248.48185)
		(mid 343.139823 -248.557686)
		(end 342.861392 -248.487946)
		(width 0.088646)
		(layer "In6.Cu")
		(net "M_A_CPU0_SB_RSP<0>")
	)
	(arc
		(start 340.031832 -248.48185)
		(mid 339.844634 -248.431707)
		(end 339.657436 -248.48185)
		(width 0.088646)
		(layer "In6.Cu")
		(net "M_A_CPU0_SB_RSP<0>")
	)
	(arc
		(start 347.550232 -248.48185)
		(mid 347.363034 -248.431707)
		(end 347.175836 -248.48185)
		(width 0.088646)
		(layer "In6.Cu")
		(net "M_A_CPU0_SB_RSP<0>")
	)
	(arc
		(start 335.898236 -248.48185)
		(mid 335.615534 -248.557592)
		(end 335.332832 -248.48185)
		(width 0.088646)
		(layer "In6.Cu")
		(net "M_A_CPU0_SB_RSP<0>")
	)
	(arc
		(start 336.272632 -248.48185)
		(mid 336.085434 -248.431707)
		(end 335.898236 -248.48185)
		(width 0.088646)
		(layer "In6.Cu")
		(net "M_A_CPU0_SB_RSP<0>")
	)
	(arc
		(start 349.055182 -248.48185)
		(mid 348.778623 -248.557559)
		(end 348.500446 -248.487946)
		(width 0.088646)
		(layer "In6.Cu")
		(net "M_A_CPU0_SB_RSP<0>")
	)
	(arc
		(start 342.476582 -248.48185)
		(mid 342.200023 -248.557559)
		(end 341.921846 -248.487946)
		(width 0.088646)
		(layer "In6.Cu")
		(net "M_A_CPU0_SB_RSP<0>")
	)
	(arc
		(start 344.730832 -248.48185)
		(mid 344.543634 -248.431707)
		(end 344.356436 -248.48185)
		(width 0.088646)
		(layer "In6.Cu")
		(net "M_A_CPU0_SB_RSP<0>")
	)
	(arc
		(start 340.597236 -248.48185)
		(mid 340.323007 -248.557775)
		(end 340.046564 -248.490486)
		(width 0.088646)
		(layer "In6.Cu")
		(net "M_A_CPU0_SB_RSP<0>")
	)
	(arc
		(start 344.356436 -248.48185)
		(mid 344.073734 -248.557592)
		(end 343.791032 -248.48185)
		(width 0.088646)
		(layer "In6.Cu")
		(net "M_A_CPU0_SB_RSP<0>")
	)
	(arc
		(start 349.429578 -248.48185)
		(mid 349.24238 -248.431707)
		(end 349.055182 -248.48185)
		(width 0.088646)
		(layer "In6.Cu")
		(net "M_A_CPU0_SB_RSP<0>")
	)
	(arc
		(start 341.537036 -248.48185)
		(mid 341.262807 -248.557775)
		(end 340.986364 -248.490486)
		(width 0.088646)
		(layer "In6.Cu")
		(net "M_A_CPU0_SB_RSP<0>")
	)
	(arc
		(start 345.670632 -248.48185)
		(mid 345.483434 -248.431707)
		(end 345.296236 -248.48185)
		(width 0.088646)
		(layer "In6.Cu")
		(net "M_A_CPU0_SB_RSP<0>")
	)
	(arc
		(start 346.610432 -248.48185)
		(mid 346.423234 -248.431707)
		(end 346.236036 -248.48185)
		(width 0.088646)
		(layer "In6.Cu")
		(net "M_A_CPU0_SB_RSP<0>")
	)
	(arc
		(start 336.838036 -248.48185)
		(mid 336.563807 -248.557775)
		(end 336.287364 -248.490486)
		(width 0.088646)
		(layer "In6.Cu")
		(net "M_A_CPU0_SB_RSP<0>")
	)
	(segment
		(start 306.616862 -246.379746)
		(end 307.0352 -246.379746)
		(width 0.20066)
		(layer "F.Cu")
		(net "M_A_CPU0_SB_PAR")
	)
	(segment
		(start 307.400706 -247.050052)
		(end 307.76291 -247.050052)
		(width 0.20066)
		(layer "F.Cu")
		(net "M_A_CPU0_SB_PAR")
	)
	(segment
		(start 314.059062 -246.860822)
		(end 313.814968 -246.616728)
		(width 0.20066)
		(layer "F.Cu")
		(net "M_A_CPU0_SB_PAR")
	)
	(segment
		(start 307.810662 -247.04167)
		(end 307.85308 -247.04167)
		(width 0.101854)
		(layer "F.Cu")
		(net "M_A_CPU0_SB_PAR")
	)
	(segment
		(start 320.590418 -247.053354)
		(end 319.907666 -247.053354)
		(width 0.20066)
		(layer "F.Cu")
		(net "M_A_CPU0_SB_PAR")
	)
	(segment
		(start 322.216018 -247.187212)
		(end 322.08216 -247.053354)
		(width 0.1016)
		(layer "F.Cu")
		(net "M_A_CPU0_SB_PAR")
	)
	(segment
		(start 306.37988 -246.616728)
		(end 306.616862 -246.379746)
		(width 0.20066)
		(layer "F.Cu")
		(net "M_A_CPU0_SB_PAR")
	)
	(segment
		(start 334.08874 -245.043706)
		(end 333.923132 -244.948202)
		(width 0.088646)
		(layer "F.Cu")
		(net "M_A_CPU0_SB_PAR")
	)
	(segment
		(start 309.98668 -247.04167)
		(end 310.088026 -247.04167)
		(width 0.101854)
		(layer "F.Cu")
		(net "M_A_CPU0_SB_PAR")
	)
	(segment
		(start 333.168498 -245.048532)
		(end 332.983332 -244.948202)
		(width 0.088646)
		(layer "F.Cu")
		(net "M_A_CPU0_SB_PAR")
	)
	(segment
		(start 312.001154 -246.616728)
		(end 312.987182 -246.616728)
		(width 0.20066)
		(layer "F.Cu")
		(net "M_A_CPU0_SB_PAR")
	)
	(segment
		(start 307.85308 -247.04167)
		(end 309.98668 -247.04167)
		(width 0.1016)
		(layer "F.Cu")
		(net "M_A_CPU0_SB_PAR")
	)
	(segment
		(start 307.80228 -247.050052)
		(end 307.810662 -247.04167)
		(width 0.101854)
		(layer "F.Cu")
		(net "M_A_CPU0_SB_PAR")
	)
	(segment
		(start 307.76291 -247.050052)
		(end 307.80228 -247.050052)
		(width 0.101854)
		(layer "F.Cu")
		(net "M_A_CPU0_SB_PAR")
	)
	(segment
		(start 311.576212 -247.04167)
		(end 312.001154 -246.616728)
		(width 0.20066)
		(layer "F.Cu")
		(net "M_A_CPU0_SB_PAR")
	)
	(segment
		(start 332.90383 -244.926866)
		(end 332.649322 -244.926866)
		(width 0.088646)
		(layer "F.Cu")
		(net "M_A_CPU0_SB_PAR")
	)
	(segment
		(start 310.088026 -247.04167)
		(end 311.576212 -247.04167)
		(width 0.20066)
		(layer "F.Cu")
		(net "M_A_CPU0_SB_PAR")
	)
	(segment
		(start 333.548736 -244.948202)
		(end 333.381096 -245.04523)
		(width 0.088646)
		(layer "F.Cu")
		(net "M_A_CPU0_SB_PAR")
	)
	(segment
		(start 322.08216 -247.053354)
		(end 320.590418 -247.053354)
		(width 0.1016)
		(layer "F.Cu")
		(net "M_A_CPU0_SB_PAR")
	)
	(segment
		(start 332.070964 -245.199916)
		(end 331.183742 -245.199916)
		(width 0.1016)
		(layer "F.Cu")
		(net "M_A_CPU0_SB_PAR")
	)
	(segment
		(start 307.0352 -246.379746)
		(end 307.24348 -246.588026)
		(width 0.20066)
		(layer "F.Cu")
		(net "M_A_CPU0_SB_PAR")
	)
	(segment
		(start 334.541622 -244.917722)
		(end 334.322928 -245.043706)
		(width 0.088646)
		(layer "F.Cu")
		(net "M_A_CPU0_SB_PAR")
	)
	(segment
		(start 334.988154 -244.863366)
		(end 334.744314 -244.863366)
		(width 0.088646)
		(layer "F.Cu")
		(net "M_A_CPU0_SB_PAR")
	)
	(segment
		(start 329.196446 -247.187212)
		(end 322.216018 -247.187212)
		(width 0.1016)
		(layer "F.Cu")
		(net "M_A_CPU0_SB_PAR")
	)
	(segment
		(start 331.183742 -245.199916)
		(end 329.196446 -247.187212)
		(width 0.1016)
		(layer "F.Cu")
		(net "M_A_CPU0_SB_PAR")
	)
	(segment
		(start 313.814968 -246.616728)
		(end 312.987182 -246.616728)
		(width 0.20066)
		(layer "F.Cu")
		(net "M_A_CPU0_SB_PAR")
	)
	(segment
		(start 332.493112 -244.991636)
		(end 332.284832 -245.199916)
		(width 0.088646)
		(layer "F.Cu")
		(net "M_A_CPU0_SB_PAR")
	)
	(segment
		(start 319.907666 -247.053354)
		(end 319.715134 -246.860822)
		(width 0.20066)
		(layer "F.Cu")
		(net "M_A_CPU0_SB_PAR")
	)
	(segment
		(start 305.443382 -246.616728)
		(end 306.37988 -246.616728)
		(width 0.20066)
		(layer "F.Cu")
		(net "M_A_CPU0_SB_PAR")
	)
	(segment
		(start 307.24348 -246.892826)
		(end 307.400706 -247.050052)
		(width 0.20066)
		(layer "F.Cu")
		(net "M_A_CPU0_SB_PAR")
	)
	(segment
		(start 332.284832 -245.199916)
		(end 332.070964 -245.199916)
		(width 0.088646)
		(layer "F.Cu")
		(net "M_A_CPU0_SB_PAR")
	)
	(segment
		(start 319.715134 -246.860822)
		(end 314.059062 -246.860822)
		(width 0.20066)
		(layer "F.Cu")
		(net "M_A_CPU0_SB_PAR")
	)
	(segment
		(start 332.649322 -244.926866)
		(end 332.493112 -244.991636)
		(width 0.088646)
		(layer "F.Cu")
		(net "M_A_CPU0_SB_PAR")
	)
	(segment
		(start 335.615534 -245.27256)
		(end 335.360772 -245.017798)
		(width 0.088646)
		(layer "F.Cu")
		(net "M_A_CPU0_SB_PAR")
	)
	(segment
		(start 307.24348 -246.588026)
		(end 307.24348 -246.892826)
		(width 0.20066)
		(layer "F.Cu")
		(net "M_A_CPU0_SB_PAR")
	)
	(arc
		(start 333.923132 -244.948202)
		(mid 333.735934 -244.898059)
		(end 333.548736 -244.948202)
		(width 0.088646)
		(layer "F.Cu")
		(net "M_A_CPU0_SB_PAR")
	)
	(arc
		(start 334.322928 -245.043706)
		(mid 334.205834 -245.075097)
		(end 334.08874 -245.043706)
		(width 0.088646)
		(layer "F.Cu")
		(net "M_A_CPU0_SB_PAR")
	)
	(arc
		(start 334.744314 -244.863366)
		(mid 334.639398 -244.877228)
		(end 334.541622 -244.917722)
		(width 0.088646)
		(layer "F.Cu")
		(net "M_A_CPU0_SB_PAR")
	)
	(arc
		(start 335.360772 -245.017798)
		(mid 335.189828 -244.903513)
		(end 334.988154 -244.863366)
		(width 0.088646)
		(layer "F.Cu")
		(net "M_A_CPU0_SB_PAR")
	)
	(arc
		(start 332.983332 -244.948202)
		(mid 332.944993 -244.932264)
		(end 332.90383 -244.926866)
		(width 0.088646)
		(layer "F.Cu")
		(net "M_A_CPU0_SB_PAR")
	)
	(arc
		(start 333.381096 -245.04523)
		(mid 333.275231 -245.074496)
		(end 333.168498 -245.048532)
		(width 0.088646)
		(layer "F.Cu")
		(net "M_A_CPU0_SB_PAR")
	)
	(segment
		(start 332.4352 -240.616994)
		(end 332.523592 -240.705386)
		(width 0.088646)
		(layer "F.Cu")
		(net "M_A_CPU0_SB_DQS_DP<9>")
	)
	(segment
		(start 307.25364 -238.236506)
		(end 307.4162 -238.236506)
		(width 0.20066)
		(layer "F.Cu")
		(net "M_A_CPU0_SB_DQS_DP<9>")
	)
	(segment
		(start 310.57723 -238.290354)
		(end 311.229248 -238.290354)
		(width 0.20066)
		(layer "F.Cu")
		(net "M_A_CPU0_SB_DQS_DP<9>")
	)
	(segment
		(start 302.184054 -237.865158)
		(end 302.56607 -237.865158)
		(width 0.20066)
		(layer "F.Cu")
		(net "M_A_CPU0_SB_DQS_DP<9>")
	)
	(segment
		(start 328.959464 -240.44021)
		(end 328.996294 -240.40338)
		(width 0.1524)
		(layer "F.Cu")
		(net "M_A_CPU0_SB_DQS_DP<9>")
	)
	(segment
		(start 307.928264 -237.834932)
		(end 308.056788 -237.834932)
		(width 0.20066)
		(layer "F.Cu")
		(net "M_A_CPU0_SB_DQS_DP<9>")
	)
	(segment
		(start 310.152288 -237.865412)
		(end 310.57723 -238.290354)
		(width 0.20066)
		(layer "F.Cu")
		(net "M_A_CPU0_SB_DQS_DP<9>")
	)
	(segment
		(start 311.522364 -238.54156)
		(end 314.457588 -238.54156)
		(width 0.1016)
		(layer "F.Cu")
		(net "M_A_CPU0_SB_DQS_DP<9>")
	)
	(segment
		(start 301.932594 -238.116618)
		(end 302.184054 -237.865158)
		(width 0.20066)
		(layer "F.Cu")
		(net "M_A_CPU0_SB_DQS_DP<9>")
	)
	(segment
		(start 303.926494 -238.541814)
		(end 303.972214 -238.541814)
		(width 0.20066)
		(layer "F.Cu")
		(net "M_A_CPU0_SB_DQS_DP<9>")
	)
	(segment
		(start 319.497964 -238.988854)
		(end 322.12661 -240.077752)
		(width 0.20066)
		(layer "F.Cu")
		(net "M_A_CPU0_SB_DQS_DP<9>")
	)
	(segment
		(start 330.931266 -240.371376)
		(end 331.251052 -240.371376)
		(width 0.088646)
		(layer "F.Cu")
		(net "M_A_CPU0_SB_DQS_DP<9>")
	)
	(segment
		(start 332.758288 -240.75009)
		(end 332.879954 -240.732056)
		(width 0.088646)
		(layer "F.Cu")
		(net "M_A_CPU0_SB_DQS_DP<9>")
	)
	(segment
		(start 333.015336 -240.693956)
		(end 333.023972 -240.690146)
		(width 0.088646)
		(layer "F.Cu")
		(net "M_A_CPU0_SB_DQS_DP<9>")
	)
	(segment
		(start 306.907946 -238.541814)
		(end 306.948332 -238.541814)
		(width 0.20066)
		(layer "F.Cu")
		(net "M_A_CPU0_SB_DQS_DP<9>")
	)
	(segment
		(start 331.521562 -240.48339)
		(end 331.824076 -240.483136)
		(width 0.088646)
		(layer "F.Cu")
		(net "M_A_CPU0_SB_DQS_DP<9>")
	)
	(segment
		(start 301.343314 -238.116618)
		(end 301.932594 -238.116618)
		(width 0.20066)
		(layer "F.Cu")
		(net "M_A_CPU0_SB_DQS_DP<9>")
	)
	(segment
		(start 309.632604 -237.865412)
		(end 310.152288 -237.865412)
		(width 0.20066)
		(layer "F.Cu")
		(net "M_A_CPU0_SB_DQS_DP<9>")
	)
	(segment
		(start 330.877164 -240.40338)
		(end 330.899262 -240.40338)
		(width 0.088646)
		(layer "F.Cu")
		(net "M_A_CPU0_SB_DQS_DP<9>")
	)
	(segment
		(start 309.381398 -238.116618)
		(end 309.632604 -237.865412)
		(width 0.20066)
		(layer "F.Cu")
		(net "M_A_CPU0_SB_DQS_DP<9>")
	)
	(segment
		(start 302.56607 -237.865158)
		(end 302.988726 -238.287814)
		(width 0.20066)
		(layer "F.Cu")
		(net "M_A_CPU0_SB_DQS_DP<9>")
	)
	(segment
		(start 332.607666 -240.740184)
		(end 332.613254 -240.741708)
		(width 0.088646)
		(layer "F.Cu")
		(net "M_A_CPU0_SB_DQS_DP<9>")
	)
	(segment
		(start 307.4162 -238.236506)
		(end 307.604922 -238.158274)
		(width 0.20066)
		(layer "F.Cu")
		(net "M_A_CPU0_SB_DQS_DP<9>")
	)
	(segment
		(start 315.595762 -238.54156)
		(end 316.043056 -238.988854)
		(width 0.20066)
		(layer "F.Cu")
		(net "M_A_CPU0_SB_DQS_DP<9>")
	)
	(segment
		(start 322.128134 -240.07699)
		(end 323.005704 -240.44021)
		(width 0.20066)
		(layer "F.Cu")
		(net "M_A_CPU0_SB_DQS_DP<9>")
	)
	(segment
		(start 322.12661 -240.077752)
		(end 322.128134 -240.07699)
		(width 0.20066)
		(layer "F.Cu")
		(net "M_A_CPU0_SB_DQS_DP<9>")
	)
	(segment
		(start 323.005704 -240.44021)
		(end 328.921364 -240.44021)
		(width 0.20066)
		(layer "F.Cu")
		(net "M_A_CPU0_SB_DQS_DP<9>")
	)
	(segment
		(start 306.948332 -238.541814)
		(end 307.25364 -238.236506)
		(width 0.20066)
		(layer "F.Cu")
		(net "M_A_CPU0_SB_DQS_DP<9>")
	)
	(segment
		(start 332.083664 -240.590324)
		(end 332.21803 -240.616994)
		(width 0.088646)
		(layer "F.Cu")
		(net "M_A_CPU0_SB_DQS_DP<9>")
	)
	(segment
		(start 314.457588 -238.54156)
		(end 315.595762 -238.54156)
		(width 0.20066)
		(layer "F.Cu")
		(net "M_A_CPU0_SB_DQS_DP<9>")
	)
	(segment
		(start 316.043056 -238.988854)
		(end 319.497964 -238.988854)
		(width 0.20066)
		(layer "F.Cu")
		(net "M_A_CPU0_SB_DQS_DP<9>")
	)
	(segment
		(start 311.480454 -238.54156)
		(end 311.522364 -238.54156)
		(width 0.20066)
		(layer "F.Cu")
		(net "M_A_CPU0_SB_DQS_DP<9>")
	)
	(segment
		(start 328.921364 -240.44021)
		(end 328.959464 -240.44021)
		(width 0.1524)
		(layer "F.Cu")
		(net "M_A_CPU0_SB_DQS_DP<9>")
	)
	(segment
		(start 331.824076 -240.483136)
		(end 332.083664 -240.590324)
		(width 0.088646)
		(layer "F.Cu")
		(net "M_A_CPU0_SB_DQS_DP<9>")
	)
	(segment
		(start 328.996294 -240.40338)
		(end 330.877164 -240.40338)
		(width 0.1524)
		(layer "F.Cu")
		(net "M_A_CPU0_SB_DQS_DP<9>")
	)
	(segment
		(start 331.251052 -240.371376)
		(end 331.521562 -240.48339)
		(width 0.088646)
		(layer "F.Cu")
		(net "M_A_CPU0_SB_DQS_DP<9>")
	)
	(segment
		(start 307.604922 -238.158274)
		(end 307.928264 -237.834932)
		(width 0.20066)
		(layer "F.Cu")
		(net "M_A_CPU0_SB_DQS_DP<9>")
	)
	(segment
		(start 311.229248 -238.290354)
		(end 311.480454 -238.54156)
		(width 0.20066)
		(layer "F.Cu")
		(net "M_A_CPU0_SB_DQS_DP<9>")
	)
	(segment
		(start 303.672494 -238.287814)
		(end 303.926494 -238.541814)
		(width 0.20066)
		(layer "F.Cu")
		(net "M_A_CPU0_SB_DQS_DP<9>")
	)
	(segment
		(start 330.899262 -240.40338)
		(end 330.931266 -240.371376)
		(width 0.088646)
		(layer "F.Cu")
		(net "M_A_CPU0_SB_DQS_DP<9>")
	)
	(segment
		(start 308.338474 -238.116618)
		(end 308.887114 -238.116618)
		(width 0.20066)
		(layer "F.Cu")
		(net "M_A_CPU0_SB_DQS_DP<9>")
	)
	(segment
		(start 303.972214 -238.541814)
		(end 306.907946 -238.541814)
		(width 0.1016)
		(layer "F.Cu")
		(net "M_A_CPU0_SB_DQS_DP<9>")
	)
	(segment
		(start 302.988726 -238.287814)
		(end 303.672494 -238.287814)
		(width 0.20066)
		(layer "F.Cu")
		(net "M_A_CPU0_SB_DQS_DP<9>")
	)
	(segment
		(start 308.056788 -237.834932)
		(end 308.338474 -238.116618)
		(width 0.20066)
		(layer "F.Cu")
		(net "M_A_CPU0_SB_DQS_DP<9>")
	)
	(segment
		(start 332.21803 -240.616994)
		(end 332.4352 -240.616994)
		(width 0.088646)
		(layer "F.Cu")
		(net "M_A_CPU0_SB_DQS_DP<9>")
	)
	(segment
		(start 333.64678 -240.389156)
		(end 333.735934 -240.389156)
		(width 0.088646)
		(layer "F.Cu")
		(net "M_A_CPU0_SB_DQS_DP<9>")
	)
	(segment
		(start 308.887114 -238.116618)
		(end 309.381398 -238.116618)
		(width 0.20066)
		(layer "F.Cu")
		(net "M_A_CPU0_SB_DQS_DP<9>")
	)
	(arc
		(start 333.023972 -240.690146)
		(mid 333.112284 -240.642251)
		(end 333.189834 -240.578386)
		(width 0.088646)
		(layer "F.Cu")
		(net "M_A_CPU0_SB_DQS_DP<9>")
	)
	(arc
		(start 332.879954 -240.732056)
		(mid 332.948856 -240.71731)
		(end 333.015336 -240.693956)
		(width 0.088646)
		(layer "F.Cu")
		(net "M_A_CPU0_SB_DQS_DP<9>")
	)
	(arc
		(start 332.613254 -240.741708)
		(mid 332.685341 -240.753329)
		(end 332.758288 -240.75009)
		(width 0.088646)
		(layer "F.Cu")
		(net "M_A_CPU0_SB_DQS_DP<9>")
	)
	(arc
		(start 332.523592 -240.705386)
		(mid 332.562165 -240.73116)
		(end 332.607666 -240.740184)
		(width 0.088646)
		(layer "F.Cu")
		(net "M_A_CPU0_SB_DQS_DP<9>")
	)
	(arc
		(start 333.189834 -240.578386)
		(mid 333.399483 -240.438303)
		(end 333.64678 -240.389156)
		(width 0.088646)
		(layer "F.Cu")
		(net "M_A_CPU0_SB_DQS_DP<9>")
	)
	(segment
		(start 307.568854 -198.585328)
		(end 307.76291 -198.585328)
		(width 0.20066)
		(layer "F.Cu")
		(net "M_A_CPU0_SB_DQS_DP<8>")
	)
	(segment
		(start 319.25895 -199.272906)
		(end 319.38341 -199.148446)
		(width 0.20066)
		(layer "F.Cu")
		(net "M_A_CPU0_SB_DQS_DP<8>")
	)
	(segment
		(start 333.078582 -220.36659)
		(end 333.081122 -220.36786)
		(width 0.088646)
		(layer "F.Cu")
		(net "M_A_CPU0_SB_DQS_DP<8>")
	)
	(segment
		(start 333.104744 -220.38056)
		(end 333.105506 -220.381068)
		(width 0.088646)
		(layer "F.Cu")
		(net "M_A_CPU0_SB_DQS_DP<8>")
	)
	(segment
		(start 306.940204 -198.851266)
		(end 307.302916 -198.851266)
		(width 0.20066)
		(layer "F.Cu")
		(net "M_A_CPU0_SB_DQS_DP<8>")
	)
	(segment
		(start 333.111348 -220.384116)
		(end 333.11211 -220.38437)
		(width 0.088646)
		(layer "F.Cu")
		(net "M_A_CPU0_SB_DQS_DP<8>")
	)
	(segment
		(start 319.98539 -199.148446)
		(end 320.10985 -199.272906)
		(width 0.20066)
		(layer "F.Cu")
		(net "M_A_CPU0_SB_DQS_DP<8>")
	)
	(segment
		(start 323.981826 -200.94067)
		(end 324.157848 -200.94067)
		(width 0.20066)
		(layer "F.Cu")
		(net "M_A_CPU0_SB_DQS_DP<8>")
	)
	(segment
		(start 334.570832 -220.855794)
		(end 334.675734 -220.855794)
		(width 0.088646)
		(layer "F.Cu")
		(net "M_A_CPU0_SB_DQS_DP<8>")
	)
	(segment
		(start 313.566556 -199.016366)
		(end 313.823096 -199.272906)
		(width 0.20066)
		(layer "F.Cu")
		(net "M_A_CPU0_SB_DQS_DP<8>")
	)
	(segment
		(start 329.720956 -206.503778)
		(end 329.720956 -206.6798)
		(width 0.20066)
		(layer "F.Cu")
		(net "M_A_CPU0_SB_DQS_DP<8>")
	)
	(segment
		(start 334.482694 -220.767656)
		(end 334.570832 -220.855794)
		(width 0.088646)
		(layer "F.Cu")
		(net "M_A_CPU0_SB_DQS_DP<8>")
	)
	(segment
		(start 332.86954 -220.175582)
		(end 333.000858 -220.3069)
		(width 0.088646)
		(layer "F.Cu")
		(net "M_A_CPU0_SB_DQS_DP<8>")
	)
	(segment
		(start 332.50759 -209.466434)
		(end 332.668118 -209.854292)
		(width 0.20066)
		(layer "F.Cu")
		(net "M_A_CPU0_SB_DQS_DP<8>")
	)
	(segment
		(start 311.59831 -199.277986)
		(end 312.246264 -199.277986)
		(width 0.20066)
		(layer "F.Cu")
		(net "M_A_CPU0_SB_DQS_DP<8>")
	)
	(segment
		(start 327.240138 -204.02296)
		(end 327.666096 -204.448918)
		(width 0.20066)
		(layer "F.Cu")
		(net "M_A_CPU0_SB_DQS_DP<8>")
	)
	(segment
		(start 332.084934 -219.53093)
		(end 332.100428 -219.546424)
		(width 0.088646)
		(layer "F.Cu")
		(net "M_A_CPU0_SB_DQS_DP<8>")
	)
	(segment
		(start 329.720956 -206.6798)
		(end 330.146406 -207.10525)
		(width 0.20066)
		(layer "F.Cu")
		(net "M_A_CPU0_SB_DQS_DP<8>")
	)
	(segment
		(start 332.100428 -219.546424)
		(end 332.100428 -219.591636)
		(width 0.088646)
		(layer "F.Cu")
		(net "M_A_CPU0_SB_DQS_DP<8>")
	)
	(segment
		(start 312.987182 -199.01662)
		(end 313.566302 -199.01662)
		(width 0.20066)
		(layer "F.Cu")
		(net "M_A_CPU0_SB_DQS_DP<8>")
	)
	(segment
		(start 324.583806 -201.54265)
		(end 325.009256 -201.9681)
		(width 0.20066)
		(layer "F.Cu")
		(net "M_A_CPU0_SB_DQS_DP<8>")
	)
	(segment
		(start 332.631288 -214.593678)
		(end 331.449172 -215.775794)
		(width 0.1524)
		(layer "F.Cu")
		(net "M_A_CPU0_SB_DQS_DP<8>")
	)
	(segment
		(start 306.513484 -199.277986)
		(end 306.940204 -198.851266)
		(width 0.20066)
		(layer "F.Cu")
		(net "M_A_CPU0_SB_DQS_DP<8>")
	)
	(segment
		(start 326.638666 -203.59751)
		(end 327.064116 -204.02296)
		(width 0.20066)
		(layer "F.Cu")
		(net "M_A_CPU0_SB_DQS_DP<8>")
	)
	(segment
		(start 330.748386 -207.531208)
		(end 330.748386 -207.70723)
		(width 0.20066)
		(layer "F.Cu")
		(net "M_A_CPU0_SB_DQS_DP<8>")
	)
	(segment
		(start 328.693526 -205.476348)
		(end 328.693526 -205.65237)
		(width 0.20066)
		(layer "F.Cu")
		(net "M_A_CPU0_SB_DQS_DP<8>")
	)
	(segment
		(start 319.38341 -199.148446)
		(end 319.98539 -199.148446)
		(width 0.20066)
		(layer "F.Cu")
		(net "M_A_CPU0_SB_DQS_DP<8>")
	)
	(segment
		(start 331.173836 -208.13268)
		(end 331.349858 -208.13268)
		(width 0.20066)
		(layer "F.Cu")
		(net "M_A_CPU0_SB_DQS_DP<8>")
	)
	(segment
		(start 328.693526 -205.65237)
		(end 329.118976 -206.07782)
		(width 0.20066)
		(layer "F.Cu")
		(net "M_A_CPU0_SB_DQS_DP<8>")
	)
	(segment
		(start 333.081122 -220.36786)
		(end 333.081884 -220.368368)
		(width 0.088646)
		(layer "F.Cu")
		(net "M_A_CPU0_SB_DQS_DP<8>")
	)
	(segment
		(start 328.091546 -205.05039)
		(end 328.267568 -205.05039)
		(width 0.20066)
		(layer "F.Cu")
		(net "M_A_CPU0_SB_DQS_DP<8>")
	)
	(segment
		(start 333.081884 -220.368368)
		(end 333.104744 -220.38056)
		(width 0.088646)
		(layer "F.Cu")
		(net "M_A_CPU0_SB_DQS_DP<8>")
	)
	(segment
		(start 321.43827 -199.148446)
		(end 321.56273 -199.272906)
		(width 0.20066)
		(layer "F.Cu")
		(net "M_A_CPU0_SB_DQS_DP<8>")
	)
	(segment
		(start 310.977534 -198.863204)
		(end 311.59831 -199.277986)
		(width 0.20066)
		(layer "F.Cu")
		(net "M_A_CPU0_SB_DQS_DP<8>")
	)
	(segment
		(start 320.10985 -199.272906)
		(end 320.71183 -199.272906)
		(width 0.20066)
		(layer "F.Cu")
		(net "M_A_CPU0_SB_DQS_DP<8>")
	)
	(segment
		(start 324.583806 -201.366628)
		(end 324.583806 -201.54265)
		(width 0.20066)
		(layer "F.Cu")
		(net "M_A_CPU0_SB_DQS_DP<8>")
	)
	(segment
		(start 333.106776 -220.381576)
		(end 333.111348 -220.384116)
		(width 0.088646)
		(layer "F.Cu")
		(net "M_A_CPU0_SB_DQS_DP<8>")
	)
	(segment
		(start 307.302916 -198.851266)
		(end 307.568854 -198.585328)
		(width 0.20066)
		(layer "F.Cu")
		(net "M_A_CPU0_SB_DQS_DP<8>")
	)
	(segment
		(start 327.064116 -204.02296)
		(end 327.240138 -204.02296)
		(width 0.20066)
		(layer "F.Cu")
		(net "M_A_CPU0_SB_DQS_DP<8>")
	)
	(segment
		(start 333.113634 -220.38564)
		(end 333.121762 -220.389958)
		(width 0.088646)
		(layer "F.Cu")
		(net "M_A_CPU0_SB_DQS_DP<8>")
	)
	(segment
		(start 306.17922 -199.277986)
		(end 306.513484 -199.277986)
		(width 0.20066)
		(layer "F.Cu")
		(net "M_A_CPU0_SB_DQS_DP<8>")
	)
	(segment
		(start 332.100428 -219.591636)
		(end 332.684628 -220.175836)
		(width 0.088646)
		(layer "F.Cu")
		(net "M_A_CPU0_SB_DQS_DP<8>")
	)
	(segment
		(start 333.112872 -220.384878)
		(end 333.112872 -220.385132)
		(width 0.088646)
		(layer "F.Cu")
		(net "M_A_CPU0_SB_DQS_DP<8>")
	)
	(segment
		(start 312.50763 -199.01662)
		(end 312.987182 -199.01662)
		(width 0.20066)
		(layer "F.Cu")
		(net "M_A_CPU0_SB_DQS_DP<8>")
	)
	(segment
		(start 325.611236 -202.394058)
		(end 325.611236 -202.57008)
		(width 0.20066)
		(layer "F.Cu")
		(net "M_A_CPU0_SB_DQS_DP<8>")
	)
	(segment
		(start 320.71183 -199.272906)
		(end 320.83629 -199.148446)
		(width 0.20066)
		(layer "F.Cu")
		(net "M_A_CPU0_SB_DQS_DP<8>")
	)
	(segment
		(start 334.018382 -220.363796)
		(end 334.36433 -220.537024)
		(width 0.088646)
		(layer "F.Cu")
		(net "M_A_CPU0_SB_DQS_DP<8>")
	)
	(segment
		(start 333.11211 -220.38437)
		(end 333.112872 -220.384878)
		(width 0.088646)
		(layer "F.Cu")
		(net "M_A_CPU0_SB_DQS_DP<8>")
	)
	(segment
		(start 332.668118 -209.854292)
		(end 332.668118 -214.033608)
		(width 0.20066)
		(layer "F.Cu")
		(net "M_A_CPU0_SB_DQS_DP<8>")
	)
	(segment
		(start 332.684628 -220.175836)
		(end 332.86954 -220.175582)
		(width 0.088646)
		(layer "F.Cu")
		(net "M_A_CPU0_SB_DQS_DP<8>")
	)
	(segment
		(start 329.294998 -206.07782)
		(end 329.720956 -206.503778)
		(width 0.20066)
		(layer "F.Cu")
		(net "M_A_CPU0_SB_DQS_DP<8>")
	)
	(segment
		(start 310.088026 -198.591932)
		(end 310.211216 -198.591932)
		(width 0.20066)
		(layer "F.Cu")
		(net "M_A_CPU0_SB_DQS_DP<8>")
	)
	(segment
		(start 307.76926 -198.591678)
		(end 310.087772 -198.591678)
		(width 0.1016)
		(layer "F.Cu")
		(net "M_A_CPU0_SB_DQS_DP<8>")
	)
	(segment
		(start 329.118976 -206.07782)
		(end 329.294998 -206.07782)
		(width 0.20066)
		(layer "F.Cu")
		(net "M_A_CPU0_SB_DQS_DP<8>")
	)
	(segment
		(start 313.823096 -199.272906)
		(end 319.25895 -199.272906)
		(width 0.20066)
		(layer "F.Cu")
		(net "M_A_CPU0_SB_DQS_DP<8>")
	)
	(segment
		(start 327.666096 -204.448918)
		(end 327.666096 -204.62494)
		(width 0.20066)
		(layer "F.Cu")
		(net "M_A_CPU0_SB_DQS_DP<8>")
	)
	(segment
		(start 330.748386 -207.70723)
		(end 331.173836 -208.13268)
		(width 0.20066)
		(layer "F.Cu")
		(net "M_A_CPU0_SB_DQS_DP<8>")
	)
	(segment
		(start 310.211216 -198.591932)
		(end 310.482488 -198.863204)
		(width 0.20066)
		(layer "F.Cu")
		(net "M_A_CPU0_SB_DQS_DP<8>")
	)
	(segment
		(start 312.246264 -199.277986)
		(end 312.50763 -199.01662)
		(width 0.20066)
		(layer "F.Cu")
		(net "M_A_CPU0_SB_DQS_DP<8>")
	)
	(segment
		(start 333.112872 -220.385132)
		(end 333.113634 -220.38564)
		(width 0.088646)
		(layer "F.Cu")
		(net "M_A_CPU0_SB_DQS_DP<8>")
	)
	(segment
		(start 333.579724 -220.32341)
		(end 333.847694 -220.32341)
		(width 0.088646)
		(layer "F.Cu")
		(net "M_A_CPU0_SB_DQS_DP<8>")
	)
	(segment
		(start 310.087772 -198.591678)
		(end 310.088026 -198.591932)
		(width 0.1016)
		(layer "F.Cu")
		(net "M_A_CPU0_SB_DQS_DP<8>")
	)
	(segment
		(start 326.212708 -202.99553)
		(end 326.638666 -203.421488)
		(width 0.20066)
		(layer "F.Cu")
		(net "M_A_CPU0_SB_DQS_DP<8>")
	)
	(segment
		(start 331.349858 -208.13268)
		(end 331.775562 -208.558384)
		(width 0.20066)
		(layer "F.Cu")
		(net "M_A_CPU0_SB_DQS_DP<8>")
	)
	(segment
		(start 330.146406 -207.10525)
		(end 330.322428 -207.10525)
		(width 0.20066)
		(layer "F.Cu")
		(net "M_A_CPU0_SB_DQS_DP<8>")
	)
	(segment
		(start 307.76291 -198.585328)
		(end 307.76926 -198.591678)
		(width 0.101854)
		(layer "F.Cu")
		(net "M_A_CPU0_SB_DQS_DP<8>")
	)
	(segment
		(start 305.443382 -199.01662)
		(end 305.917854 -199.01662)
		(width 0.20066)
		(layer "F.Cu")
		(net "M_A_CPU0_SB_DQS_DP<8>")
	)
	(segment
		(start 331.449172 -215.775794)
		(end 331.449172 -218.895168)
		(width 0.1524)
		(layer "F.Cu")
		(net "M_A_CPU0_SB_DQS_DP<8>")
	)
	(segment
		(start 320.83629 -199.148446)
		(end 321.43827 -199.148446)
		(width 0.20066)
		(layer "F.Cu")
		(net "M_A_CPU0_SB_DQS_DP<8>")
	)
	(segment
		(start 326.638666 -203.421488)
		(end 326.638666 -203.59751)
		(width 0.20066)
		(layer "F.Cu")
		(net "M_A_CPU0_SB_DQS_DP<8>")
	)
	(segment
		(start 332.631288 -214.108538)
		(end 332.631288 -214.593678)
		(width 0.1524)
		(layer "F.Cu")
		(net "M_A_CPU0_SB_DQS_DP<8>")
	)
	(segment
		(start 324.157848 -200.94067)
		(end 324.583806 -201.366628)
		(width 0.20066)
		(layer "F.Cu")
		(net "M_A_CPU0_SB_DQS_DP<8>")
	)
	(segment
		(start 313.566302 -199.01662)
		(end 313.566556 -199.016366)
		(width 0.20066)
		(layer "F.Cu")
		(net "M_A_CPU0_SB_DQS_DP<8>")
	)
	(segment
		(start 327.666096 -204.62494)
		(end 328.091546 -205.05039)
		(width 0.20066)
		(layer "F.Cu")
		(net "M_A_CPU0_SB_DQS_DP<8>")
	)
	(segment
		(start 328.267568 -205.05039)
		(end 328.693526 -205.476348)
		(width 0.20066)
		(layer "F.Cu")
		(net "M_A_CPU0_SB_DQS_DP<8>")
	)
	(segment
		(start 332.668118 -214.033608)
		(end 332.668118 -214.071708)
		(width 0.1524)
		(layer "F.Cu")
		(net "M_A_CPU0_SB_DQS_DP<8>")
	)
	(segment
		(start 333.313532 -220.405198)
		(end 333.421228 -220.356176)
		(width 0.088646)
		(layer "F.Cu")
		(net "M_A_CPU0_SB_DQS_DP<8>")
	)
	(segment
		(start 326.036686 -202.99553)
		(end 326.212708 -202.99553)
		(width 0.20066)
		(layer "F.Cu")
		(net "M_A_CPU0_SB_DQS_DP<8>")
	)
	(segment
		(start 321.56273 -199.272906)
		(end 322.314062 -199.272906)
		(width 0.20066)
		(layer "F.Cu")
		(net "M_A_CPU0_SB_DQS_DP<8>")
	)
	(segment
		(start 322.314062 -199.272906)
		(end 323.981826 -200.94067)
		(width 0.20066)
		(layer "F.Cu")
		(net "M_A_CPU0_SB_DQS_DP<8>")
	)
	(segment
		(start 331.775562 -208.734406)
		(end 332.50759 -209.466434)
		(width 0.20066)
		(layer "F.Cu")
		(net "M_A_CPU0_SB_DQS_DP<8>")
	)
	(segment
		(start 305.917854 -199.01662)
		(end 306.17922 -199.277986)
		(width 0.20066)
		(layer "F.Cu")
		(net "M_A_CPU0_SB_DQS_DP<8>")
	)
	(segment
		(start 332.668118 -214.071708)
		(end 332.631288 -214.108538)
		(width 0.1524)
		(layer "F.Cu")
		(net "M_A_CPU0_SB_DQS_DP<8>")
	)
	(segment
		(start 310.482488 -198.863204)
		(end 310.977534 -198.863204)
		(width 0.20066)
		(layer "F.Cu")
		(net "M_A_CPU0_SB_DQS_DP<8>")
	)
	(segment
		(start 331.775562 -208.558384)
		(end 331.775562 -208.734406)
		(width 0.20066)
		(layer "F.Cu")
		(net "M_A_CPU0_SB_DQS_DP<8>")
	)
	(segment
		(start 325.009256 -201.9681)
		(end 325.185278 -201.9681)
		(width 0.20066)
		(layer "F.Cu")
		(net "M_A_CPU0_SB_DQS_DP<8>")
	)
	(segment
		(start 331.449172 -218.895168)
		(end 332.084934 -219.53093)
		(width 0.1524)
		(layer "F.Cu")
		(net "M_A_CPU0_SB_DQS_DP<8>")
	)
	(segment
		(start 325.611236 -202.57008)
		(end 326.036686 -202.99553)
		(width 0.20066)
		(layer "F.Cu")
		(net "M_A_CPU0_SB_DQS_DP<8>")
	)
	(segment
		(start 333.105506 -220.381068)
		(end 333.106776 -220.381576)
		(width 0.088646)
		(layer "F.Cu")
		(net "M_A_CPU0_SB_DQS_DP<8>")
	)
	(segment
		(start 325.185278 -201.9681)
		(end 325.611236 -202.394058)
		(width 0.20066)
		(layer "F.Cu")
		(net "M_A_CPU0_SB_DQS_DP<8>")
	)
	(segment
		(start 330.322428 -207.10525)
		(end 330.748386 -207.531208)
		(width 0.20066)
		(layer "F.Cu")
		(net "M_A_CPU0_SB_DQS_DP<8>")
	)
	(segment
		(start 334.36433 -220.537024)
		(end 334.482694 -220.767656)
		(width 0.088646)
		(layer "F.Cu")
		(net "M_A_CPU0_SB_DQS_DP<8>")
	)
	(arc
		(start 333.121762 -220.389958)
		(mid 333.172337 -220.410308)
		(end 333.225902 -220.420438)
		(width 0.088646)
		(layer "F.Cu")
		(net "M_A_CPU0_SB_DQS_DP<8>")
	)
	(arc
		(start 333.000858 -220.3069)
		(mid 333.037764 -220.339291)
		(end 333.078582 -220.36659)
		(width 0.088646)
		(layer "F.Cu")
		(net "M_A_CPU0_SB_DQS_DP<8>")
	)
	(arc
		(start 333.225902 -220.420438)
		(mid 333.270708 -220.418512)
		(end 333.313532 -220.405198)
		(width 0.088646)
		(layer "F.Cu")
		(net "M_A_CPU0_SB_DQS_DP<8>")
	)
	(arc
		(start 333.421228 -220.356176)
		(mid 333.498794 -220.331667)
		(end 333.579724 -220.32341)
		(width 0.088646)
		(layer "F.Cu")
		(net "M_A_CPU0_SB_DQS_DP<8>")
	)
	(arc
		(start 333.847694 -220.32341)
		(mid 333.935399 -220.333635)
		(end 334.018382 -220.363796)
		(width 0.088646)
		(layer "F.Cu")
		(net "M_A_CPU0_SB_DQS_DP<8>")
	)
	(segment
		(start 321.843908 -210.721448)
		(end 321.843908 -210.89747)
		(width 0.20066)
		(layer "F.Cu")
		(net "M_A_CPU0_SB_DQS_DP<7>")
	)
	(segment
		(start 318.409066 -208.666588)
		(end 319.011046 -208.666588)
		(width 0.20066)
		(layer "F.Cu")
		(net "M_A_CPU0_SB_DQS_DP<7>")
	)
	(segment
		(start 331.92593 -230.089964)
		(end 332.428342 -230.089964)
		(width 0.088646)
		(layer "F.Cu")
		(net "M_A_CPU0_SB_DQS_DP<7>")
	)
	(segment
		(start 318.284606 -208.791048)
		(end 318.409066 -208.666588)
		(width 0.20066)
		(layer "F.Cu")
		(net "M_A_CPU0_SB_DQS_DP<7>")
	)
	(segment
		(start 323.898768 -212.776308)
		(end 323.898768 -212.95233)
		(width 0.20066)
		(layer "F.Cu")
		(net "M_A_CPU0_SB_DQS_DP<7>")
	)
	(segment
		(start 316.831726 -208.791048)
		(end 316.956186 -208.666588)
		(width 0.20066)
		(layer "F.Cu")
		(net "M_A_CPU0_SB_DQS_DP<7>")
	)
	(segment
		(start 323.47281 -212.35035)
		(end 323.898768 -212.776308)
		(width 0.20066)
		(layer "F.Cu")
		(net "M_A_CPU0_SB_DQS_DP<7>")
	)
	(segment
		(start 331.691488 -230.058214)
		(end 331.872082 -230.058214)
		(width 0.1524)
		(layer "F.Cu")
		(net "M_A_CPU0_SB_DQS_DP<7>")
	)
	(segment
		(start 320.214498 -209.26806)
		(end 320.39052 -209.26806)
		(width 0.20066)
		(layer "F.Cu")
		(net "M_A_CPU0_SB_DQS_DP<7>")
	)
	(segment
		(start 312.987182 -208.366614)
		(end 313.524392 -208.366614)
		(width 0.20066)
		(layer "F.Cu")
		(net "M_A_CPU0_SB_DQS_DP<7>")
	)
	(segment
		(start 325.953628 -215.00719)
		(end 326.379078 -215.43264)
		(width 0.20066)
		(layer "F.Cu")
		(net "M_A_CPU0_SB_DQS_DP<7>")
	)
	(segment
		(start 316.105286 -208.666588)
		(end 316.229746 -208.791048)
		(width 0.20066)
		(layer "F.Cu")
		(net "M_A_CPU0_SB_DQS_DP<7>")
	)
	(segment
		(start 321.41795 -210.29549)
		(end 321.843908 -210.721448)
		(width 0.20066)
		(layer "F.Cu")
		(net "M_A_CPU0_SB_DQS_DP<7>")
	)
	(segment
		(start 321.241928 -210.29549)
		(end 321.41795 -210.29549)
		(width 0.20066)
		(layer "F.Cu")
		(net "M_A_CPU0_SB_DQS_DP<7>")
	)
	(segment
		(start 313.524392 -208.366614)
		(end 313.948826 -208.791048)
		(width 0.20066)
		(layer "F.Cu")
		(net "M_A_CPU0_SB_DQS_DP<7>")
	)
	(segment
		(start 328.385932 -224.613216)
		(end 328.385932 -226.752658)
		(width 0.1524)
		(layer "F.Cu")
		(net "M_A_CPU0_SB_DQS_DP<7>")
	)
	(segment
		(start 315.503306 -208.666588)
		(end 316.105286 -208.666588)
		(width 0.20066)
		(layer "F.Cu")
		(net "M_A_CPU0_SB_DQS_DP<7>")
	)
	(segment
		(start 315.378846 -208.791048)
		(end 315.503306 -208.666588)
		(width 0.20066)
		(layer "F.Cu")
		(net "M_A_CPU0_SB_DQS_DP<7>")
	)
	(segment
		(start 307.778658 -207.941672)
		(end 310.077612 -207.941672)
		(width 0.1016)
		(layer "F.Cu")
		(net "M_A_CPU0_SB_DQS_DP<7>")
	)
	(segment
		(start 323.296788 -212.35035)
		(end 323.47281 -212.35035)
		(width 0.20066)
		(layer "F.Cu")
		(net "M_A_CPU0_SB_DQS_DP<7>")
	)
	(segment
		(start 320.39052 -209.26806)
		(end 320.816478 -209.694018)
		(width 0.20066)
		(layer "F.Cu")
		(net "M_A_CPU0_SB_DQS_DP<7>")
	)
	(segment
		(start 319.135506 -208.791048)
		(end 319.737486 -208.791048)
		(width 0.20066)
		(layer "F.Cu")
		(net "M_A_CPU0_SB_DQS_DP<7>")
	)
	(segment
		(start 306.836064 -208.20126)
		(end 307.123084 -208.20126)
		(width 0.20066)
		(layer "F.Cu")
		(net "M_A_CPU0_SB_DQS_DP<7>")
	)
	(segment
		(start 306.409344 -208.62798)
		(end 306.836064 -208.20126)
		(width 0.20066)
		(layer "F.Cu")
		(net "M_A_CPU0_SB_DQS_DP<7>")
	)
	(segment
		(start 325.52767 -214.40521)
		(end 325.953628 -214.831168)
		(width 0.20066)
		(layer "F.Cu")
		(net "M_A_CPU0_SB_DQS_DP<7>")
	)
	(segment
		(start 334.006952 -230.126286)
		(end 334.00746 -230.126794)
		(width 0.088646)
		(layer "F.Cu")
		(net "M_A_CPU0_SB_DQS_DP<7>")
	)
	(segment
		(start 320.816478 -209.87004)
		(end 321.241928 -210.29549)
		(width 0.20066)
		(layer "F.Cu")
		(net "M_A_CPU0_SB_DQS_DP<7>")
	)
	(segment
		(start 328.385932 -226.752658)
		(end 331.691488 -230.058214)
		(width 0.1524)
		(layer "F.Cu")
		(net "M_A_CPU0_SB_DQS_DP<7>")
	)
	(segment
		(start 313.948826 -208.791048)
		(end 315.378846 -208.791048)
		(width 0.20066)
		(layer "F.Cu")
		(net "M_A_CPU0_SB_DQS_DP<7>")
	)
	(segment
		(start 326.405748 -215.510872)
		(end 326.667114 -215.772238)
		(width 0.1524)
		(layer "F.Cu")
		(net "M_A_CPU0_SB_DQS_DP<7>")
	)
	(segment
		(start 306.17922 -208.62798)
		(end 306.409344 -208.62798)
		(width 0.20066)
		(layer "F.Cu")
		(net "M_A_CPU0_SB_DQS_DP<7>")
	)
	(segment
		(start 307.123084 -208.20126)
		(end 307.39842 -207.925924)
		(width 0.20066)
		(layer "F.Cu")
		(net "M_A_CPU0_SB_DQS_DP<7>")
	)
	(segment
		(start 310.435244 -207.931258)
		(end 310.70931 -208.205324)
		(width 0.20066)
		(layer "F.Cu")
		(net "M_A_CPU0_SB_DQS_DP<7>")
	)
	(segment
		(start 322.44538 -211.32292)
		(end 322.871338 -211.748878)
		(width 0.20066)
		(layer "F.Cu")
		(net "M_A_CPU0_SB_DQS_DP<7>")
	)
	(segment
		(start 331.89418 -230.058214)
		(end 331.92593 -230.089964)
		(width 0.088646)
		(layer "F.Cu")
		(net "M_A_CPU0_SB_DQS_DP<7>")
	)
	(segment
		(start 317.558166 -208.666588)
		(end 317.682626 -208.791048)
		(width 0.20066)
		(layer "F.Cu")
		(net "M_A_CPU0_SB_DQS_DP<7>")
	)
	(segment
		(start 325.351648 -214.40521)
		(end 325.52767 -214.40521)
		(width 0.20066)
		(layer "F.Cu")
		(net "M_A_CPU0_SB_DQS_DP<7>")
	)
	(segment
		(start 324.926198 -213.803738)
		(end 324.926198 -213.97976)
		(width 0.20066)
		(layer "F.Cu")
		(net "M_A_CPU0_SB_DQS_DP<7>")
	)
	(segment
		(start 332.460854 -230.057452)
		(end 332.796388 -230.057452)
		(width 0.088646)
		(layer "F.Cu")
		(net "M_A_CPU0_SB_DQS_DP<7>")
	)
	(segment
		(start 324.324218 -213.37778)
		(end 324.50024 -213.37778)
		(width 0.20066)
		(layer "F.Cu")
		(net "M_A_CPU0_SB_DQS_DP<7>")
	)
	(segment
		(start 326.780652 -223.007936)
		(end 328.385932 -224.613216)
		(width 0.1524)
		(layer "F.Cu")
		(net "M_A_CPU0_SB_DQS_DP<7>")
	)
	(segment
		(start 305.443382 -208.366614)
		(end 305.917854 -208.366614)
		(width 0.20066)
		(layer "F.Cu")
		(net "M_A_CPU0_SB_DQS_DP<7>")
	)
	(segment
		(start 307.76291 -207.925924)
		(end 307.778658 -207.941672)
		(width 0.1016)
		(layer "F.Cu")
		(net "M_A_CPU0_SB_DQS_DP<7>")
	)
	(segment
		(start 321.843908 -210.89747)
		(end 322.269358 -211.32292)
		(width 0.20066)
		(layer "F.Cu")
		(net "M_A_CPU0_SB_DQS_DP<7>")
	)
	(segment
		(start 325.953628 -214.831168)
		(end 325.953628 -215.00719)
		(width 0.20066)
		(layer "F.Cu")
		(net "M_A_CPU0_SB_DQS_DP<7>")
	)
	(segment
		(start 316.956186 -208.666588)
		(end 317.558166 -208.666588)
		(width 0.20066)
		(layer "F.Cu")
		(net "M_A_CPU0_SB_DQS_DP<7>")
	)
	(segment
		(start 326.780652 -216.915492)
		(end 326.780652 -223.007936)
		(width 0.1524)
		(layer "F.Cu")
		(net "M_A_CPU0_SB_DQS_DP<7>")
	)
	(segment
		(start 332.428342 -230.089964)
		(end 332.460854 -230.057452)
		(width 0.088646)
		(layer "F.Cu")
		(net "M_A_CPU0_SB_DQS_DP<7>")
	)
	(segment
		(start 334.00746 -230.126794)
		(end 334.368394 -230.307134)
		(width 0.088646)
		(layer "F.Cu")
		(net "M_A_CPU0_SB_DQS_DP<7>")
	)
	(segment
		(start 310.088026 -207.931258)
		(end 310.435244 -207.931258)
		(width 0.20066)
		(layer "F.Cu")
		(net "M_A_CPU0_SB_DQS_DP<7>")
	)
	(segment
		(start 320.816478 -209.694018)
		(end 320.816478 -209.87004)
		(width 0.20066)
		(layer "F.Cu")
		(net "M_A_CPU0_SB_DQS_DP<7>")
	)
	(segment
		(start 334.570832 -230.622602)
		(end 334.675734 -230.622602)
		(width 0.088646)
		(layer "F.Cu")
		(net "M_A_CPU0_SB_DQS_DP<7>")
	)
	(segment
		(start 326.667114 -215.772238)
		(end 326.667114 -216.641426)
		(width 0.1524)
		(layer "F.Cu")
		(net "M_A_CPU0_SB_DQS_DP<7>")
	)
	(segment
		(start 326.379078 -215.43264)
		(end 326.406002 -215.459564)
		(width 0.1524)
		(layer "F.Cu")
		(net "M_A_CPU0_SB_DQS_DP<7>")
	)
	(segment
		(start 324.50024 -213.37778)
		(end 324.926198 -213.803738)
		(width 0.20066)
		(layer "F.Cu")
		(net "M_A_CPU0_SB_DQS_DP<7>")
	)
	(segment
		(start 326.406002 -215.459564)
		(end 326.405748 -215.510872)
		(width 0.1524)
		(layer "F.Cu")
		(net "M_A_CPU0_SB_DQS_DP<7>")
	)
	(segment
		(start 334.486504 -230.538274)
		(end 334.570832 -230.622602)
		(width 0.088646)
		(layer "F.Cu")
		(net "M_A_CPU0_SB_DQS_DP<7>")
	)
	(segment
		(start 323.898768 -212.95233)
		(end 324.324218 -213.37778)
		(width 0.20066)
		(layer "F.Cu")
		(net "M_A_CPU0_SB_DQS_DP<7>")
	)
	(segment
		(start 305.917854 -208.366614)
		(end 306.17922 -208.62798)
		(width 0.20066)
		(layer "F.Cu")
		(net "M_A_CPU0_SB_DQS_DP<7>")
	)
	(segment
		(start 334.368394 -230.307134)
		(end 334.486504 -230.538274)
		(width 0.088646)
		(layer "F.Cu")
		(net "M_A_CPU0_SB_DQS_DP<7>")
	)
	(segment
		(start 324.926198 -213.97976)
		(end 325.351648 -214.40521)
		(width 0.20066)
		(layer "F.Cu")
		(net "M_A_CPU0_SB_DQS_DP<7>")
	)
	(segment
		(start 307.39842 -207.925924)
		(end 307.76291 -207.925924)
		(width 0.20066)
		(layer "F.Cu")
		(net "M_A_CPU0_SB_DQS_DP<7>")
	)
	(segment
		(start 311.173876 -208.205324)
		(end 311.806336 -208.62798)
		(width 0.20066)
		(layer "F.Cu")
		(net "M_A_CPU0_SB_DQS_DP<7>")
	)
	(segment
		(start 312.246264 -208.62798)
		(end 312.50763 -208.366614)
		(width 0.20066)
		(layer "F.Cu")
		(net "M_A_CPU0_SB_DQS_DP<7>")
	)
	(segment
		(start 322.871338 -211.748878)
		(end 322.871338 -211.9249)
		(width 0.20066)
		(layer "F.Cu")
		(net "M_A_CPU0_SB_DQS_DP<7>")
	)
	(segment
		(start 326.667114 -216.641426)
		(end 326.780652 -216.915492)
		(width 0.1524)
		(layer "F.Cu")
		(net "M_A_CPU0_SB_DQS_DP<7>")
	)
	(segment
		(start 322.269358 -211.32292)
		(end 322.44538 -211.32292)
		(width 0.20066)
		(layer "F.Cu")
		(net "M_A_CPU0_SB_DQS_DP<7>")
	)
	(segment
		(start 312.50763 -208.366614)
		(end 312.987182 -208.366614)
		(width 0.20066)
		(layer "F.Cu")
		(net "M_A_CPU0_SB_DQS_DP<7>")
	)
	(segment
		(start 319.011046 -208.666588)
		(end 319.135506 -208.791048)
		(width 0.20066)
		(layer "F.Cu")
		(net "M_A_CPU0_SB_DQS_DP<7>")
	)
	(segment
		(start 310.70931 -208.205324)
		(end 311.173876 -208.205324)
		(width 0.20066)
		(layer "F.Cu")
		(net "M_A_CPU0_SB_DQS_DP<7>")
	)
	(segment
		(start 316.229746 -208.791048)
		(end 316.831726 -208.791048)
		(width 0.20066)
		(layer "F.Cu")
		(net "M_A_CPU0_SB_DQS_DP<7>")
	)
	(segment
		(start 317.682626 -208.791048)
		(end 318.284606 -208.791048)
		(width 0.20066)
		(layer "F.Cu")
		(net "M_A_CPU0_SB_DQS_DP<7>")
	)
	(segment
		(start 310.077612 -207.941672)
		(end 310.088026 -207.931258)
		(width 0.1016)
		(layer "F.Cu")
		(net "M_A_CPU0_SB_DQS_DP<7>")
	)
	(segment
		(start 311.806336 -208.62798)
		(end 312.246264 -208.62798)
		(width 0.20066)
		(layer "F.Cu")
		(net "M_A_CPU0_SB_DQS_DP<7>")
	)
	(segment
		(start 319.737486 -208.791048)
		(end 320.214498 -209.26806)
		(width 0.20066)
		(layer "F.Cu")
		(net "M_A_CPU0_SB_DQS_DP<7>")
	)
	(segment
		(start 331.872082 -230.058214)
		(end 331.89418 -230.058214)
		(width 0.088646)
		(layer "F.Cu")
		(net "M_A_CPU0_SB_DQS_DP<7>")
	)
	(segment
		(start 322.871338 -211.9249)
		(end 323.296788 -212.35035)
		(width 0.20066)
		(layer "F.Cu")
		(net "M_A_CPU0_SB_DQS_DP<7>")
	)
	(arc
		(start 332.83271 -230.058468)
		(mid 332.959938 -230.081666)
		(end 333.078582 -230.133144)
		(width 0.088646)
		(layer "F.Cu")
		(net "M_A_CPU0_SB_DQS_DP<7>")
	)
	(arc
		(start 332.796388 -230.057452)
		(mid 332.814557 -230.057671)
		(end 332.83271 -230.058468)
		(width 0.088646)
		(layer "F.Cu")
		(net "M_A_CPU0_SB_DQS_DP<7>")
	)
	(arc
		(start 333.078582 -230.133144)
		(mid 333.26578 -230.183287)
		(end 333.452978 -230.133144)
		(width 0.088646)
		(layer "F.Cu")
		(net "M_A_CPU0_SB_DQS_DP<7>")
	)
	(arc
		(start 333.452978 -230.133144)
		(mid 333.729082 -230.057158)
		(end 334.006952 -230.126286)
		(width 0.088646)
		(layer "F.Cu")
		(net "M_A_CPU0_SB_DQS_DP<7>")
	)
	(segment
		(start 323.56933 -228.624638)
		(end 324.17131 -228.624638)
		(width 0.20066)
		(layer "F.Cu")
		(net "M_A_CPU0_SB_DQS_DP<6>")
	)
	(segment
		(start 316.407038 -218.877134)
		(end 316.58306 -218.877134)
		(width 0.20066)
		(layer "F.Cu")
		(net "M_A_CPU0_SB_DQS_DP<6>")
	)
	(segment
		(start 319.489328 -225.125534)
		(end 319.489328 -225.727514)
		(width 0.20066)
		(layer "F.Cu")
		(net "M_A_CPU0_SB_DQS_DP<6>")
	)
	(segment
		(start 330.860654 -234.819952)
		(end 331.410564 -234.819952)
		(width 0.1524)
		(layer "F.Cu")
		(net "M_A_CPU0_SB_DQS_DP<6>")
	)
	(segment
		(start 334.486504 -235.421678)
		(end 334.570832 -235.506006)
		(width 0.088646)
		(layer "F.Cu")
		(net "M_A_CPU0_SB_DQS_DP<6>")
	)
	(segment
		(start 334.368648 -235.190538)
		(end 334.468724 -235.38688)
		(width 0.088646)
		(layer "F.Cu")
		(net "M_A_CPU0_SB_DQS_DP<6>")
	)
	(segment
		(start 333.439262 -235.024676)
		(end 333.453232 -235.016548)
		(width 0.088646)
		(layer "F.Cu")
		(net "M_A_CPU0_SB_DQS_DP<6>")
	)
	(segment
		(start 312.50763 -217.716608)
		(end 312.987182 -217.716608)
		(width 0.20066)
		(layer "F.Cu")
		(net "M_A_CPU0_SB_DQS_DP<6>")
	)
	(segment
		(start 319.063878 -221.533974)
		(end 319.489328 -221.959424)
		(width 0.20066)
		(layer "F.Cu")
		(net "M_A_CPU0_SB_DQS_DP<6>")
	)
	(segment
		(start 318.461898 -220.931994)
		(end 318.63792 -220.931994)
		(width 0.20066)
		(layer "F.Cu")
		(net "M_A_CPU0_SB_DQS_DP<6>")
	)
	(segment
		(start 310.088026 -217.2843)
		(end 310.386984 -217.2843)
		(width 0.20066)
		(layer "F.Cu")
		(net "M_A_CPU0_SB_DQS_DP<6>")
	)
	(segment
		(start 314.510928 -218.09583)
		(end 315.350652 -218.09583)
		(width 0.20066)
		(layer "F.Cu")
		(net "M_A_CPU0_SB_DQS_DP<6>")
	)
	(segment
		(start 319.613788 -225.851974)
		(end 319.613788 -226.453954)
		(width 0.20066)
		(layer "F.Cu")
		(net "M_A_CPU0_SB_DQS_DP<6>")
	)
	(segment
		(start 320.649092 -228.023166)
		(end 320.649092 -228.199188)
		(width 0.20066)
		(layer "F.Cu")
		(net "M_A_CPU0_SB_DQS_DP<6>")
	)
	(segment
		(start 307.76291 -217.286332)
		(end 307.768244 -217.291666)
		(width 0.1016)
		(layer "F.Cu")
		(net "M_A_CPU0_SB_DQS_DP<6>")
	)
	(segment
		(start 334.468724 -235.38688)
		(end 334.486504 -235.421678)
		(width 0.088646)
		(layer "F.Cu")
		(net "M_A_CPU0_SB_DQS_DP<6>")
	)
	(segment
		(start 312.227468 -217.99677)
		(end 312.50763 -217.716608)
		(width 0.20066)
		(layer "F.Cu")
		(net "M_A_CPU0_SB_DQS_DP<6>")
	)
	(segment
		(start 318.036448 -220.506544)
		(end 318.461898 -220.931994)
		(width 0.20066)
		(layer "F.Cu")
		(net "M_A_CPU0_SB_DQS_DP<6>")
	)
	(segment
		(start 321.26555 -228.624638)
		(end 321.39001 -228.500178)
		(width 0.20066)
		(layer "F.Cu")
		(net "M_A_CPU0_SB_DQS_DP<6>")
	)
	(segment
		(start 324.20941 -228.624638)
		(end 324.24624 -228.661468)
		(width 0.1524)
		(layer "F.Cu")
		(net "M_A_CPU0_SB_DQS_DP<6>")
	)
	(segment
		(start 313.78144 -217.716608)
		(end 313.973464 -217.908632)
		(width 0.20066)
		(layer "F.Cu")
		(net "M_A_CPU0_SB_DQS_DP<6>")
	)
	(segment
		(start 324.24624 -228.661468)
		(end 324.70217 -228.661468)
		(width 0.1524)
		(layer "F.Cu")
		(net "M_A_CPU0_SB_DQS_DP<6>")
	)
	(segment
		(start 318.036448 -220.330522)
		(end 318.036448 -220.506544)
		(width 0.20066)
		(layer "F.Cu")
		(net "M_A_CPU0_SB_DQS_DP<6>")
	)
	(segment
		(start 320.047112 -227.597208)
		(end 320.223134 -227.597208)
		(width 0.20066)
		(layer "F.Cu")
		(net "M_A_CPU0_SB_DQS_DP<6>")
	)
	(segment
		(start 322.84289 -228.500178)
		(end 323.44487 -228.500178)
		(width 0.20066)
		(layer "F.Cu")
		(net "M_A_CPU0_SB_DQS_DP<6>")
	)
	(segment
		(start 306.833524 -217.551254)
		(end 307.107336 -217.551254)
		(width 0.20066)
		(layer "F.Cu")
		(net "M_A_CPU0_SB_DQS_DP<6>")
	)
	(segment
		(start 320.649092 -228.199188)
		(end 321.074542 -228.624638)
		(width 0.20066)
		(layer "F.Cu")
		(net "M_A_CPU0_SB_DQS_DP<6>")
	)
	(segment
		(start 319.489328 -221.959424)
		(end 319.489328 -222.821754)
		(width 0.20066)
		(layer "F.Cu")
		(net "M_A_CPU0_SB_DQS_DP<6>")
	)
	(segment
		(start 331.464412 -234.851702)
		(end 331.90307 -234.851702)
		(width 0.088646)
		(layer "F.Cu")
		(net "M_A_CPU0_SB_DQS_DP<6>")
	)
	(segment
		(start 319.613788 -226.453954)
		(end 319.489328 -226.578414)
		(width 0.20066)
		(layer "F.Cu")
		(net "M_A_CPU0_SB_DQS_DP<6>")
	)
	(segment
		(start 319.489328 -227.039424)
		(end 320.047112 -227.597208)
		(width 0.20066)
		(layer "F.Cu")
		(net "M_A_CPU0_SB_DQS_DP<6>")
	)
	(segment
		(start 314.171076 -218.235784)
		(end 314.510928 -218.09583)
		(width 0.20066)
		(layer "F.Cu")
		(net "M_A_CPU0_SB_DQS_DP<6>")
	)
	(segment
		(start 321.39001 -228.500178)
		(end 321.99199 -228.500178)
		(width 0.20066)
		(layer "F.Cu")
		(net "M_A_CPU0_SB_DQS_DP<6>")
	)
	(segment
		(start 305.917854 -217.716608)
		(end 306.17922 -217.977974)
		(width 0.20066)
		(layer "F.Cu")
		(net "M_A_CPU0_SB_DQS_DP<6>")
	)
	(segment
		(start 331.432662 -234.819952)
		(end 331.464412 -234.851702)
		(width 0.088646)
		(layer "F.Cu")
		(net "M_A_CPU0_SB_DQS_DP<6>")
	)
	(segment
		(start 310.068976 -217.291666)
		(end 310.076342 -217.2843)
		(width 0.1016)
		(layer "F.Cu")
		(net "M_A_CPU0_SB_DQS_DP<6>")
	)
	(segment
		(start 310.669686 -217.567002)
		(end 311.07126 -217.567002)
		(width 0.20066)
		(layer "F.Cu")
		(net "M_A_CPU0_SB_DQS_DP<6>")
	)
	(segment
		(start 310.076342 -217.2843)
		(end 310.088026 -217.2843)
		(width 0.1016)
		(layer "F.Cu")
		(net "M_A_CPU0_SB_DQS_DP<6>")
	)
	(segment
		(start 323.44487 -228.500178)
		(end 323.56933 -228.624638)
		(width 0.20066)
		(layer "F.Cu")
		(net "M_A_CPU0_SB_DQS_DP<6>")
	)
	(segment
		(start 319.613788 -222.946214)
		(end 319.613788 -223.548194)
		(width 0.20066)
		(layer "F.Cu")
		(net "M_A_CPU0_SB_DQS_DP<6>")
	)
	(segment
		(start 314.095892 -218.235784)
		(end 314.171076 -218.235784)
		(width 0.20066)
		(layer "F.Cu")
		(net "M_A_CPU0_SB_DQS_DP<6>")
	)
	(segment
		(start 306.17922 -217.977974)
		(end 306.406804 -217.977974)
		(width 0.20066)
		(layer "F.Cu")
		(net "M_A_CPU0_SB_DQS_DP<6>")
	)
	(segment
		(start 317.434468 -219.904564)
		(end 317.61049 -219.904564)
		(width 0.20066)
		(layer "F.Cu")
		(net "M_A_CPU0_SB_DQS_DP<6>")
	)
	(segment
		(start 333.079344 -235.017056)
		(end 333.091028 -235.024168)
		(width 0.088646)
		(layer "F.Cu")
		(net "M_A_CPU0_SB_DQS_DP<6>")
	)
	(segment
		(start 331.410564 -234.819952)
		(end 331.432662 -234.819952)
		(width 0.088646)
		(layer "F.Cu")
		(net "M_A_CPU0_SB_DQS_DP<6>")
	)
	(segment
		(start 319.489328 -226.578414)
		(end 319.489328 -227.039424)
		(width 0.20066)
		(layer "F.Cu")
		(net "M_A_CPU0_SB_DQS_DP<6>")
	)
	(segment
		(start 319.489328 -222.821754)
		(end 319.613788 -222.946214)
		(width 0.20066)
		(layer "F.Cu")
		(net "M_A_CPU0_SB_DQS_DP<6>")
	)
	(segment
		(start 316.58306 -218.877134)
		(end 317.009018 -219.303092)
		(width 0.20066)
		(layer "F.Cu")
		(net "M_A_CPU0_SB_DQS_DP<6>")
	)
	(segment
		(start 317.61049 -219.904564)
		(end 318.036448 -220.330522)
		(width 0.20066)
		(layer "F.Cu")
		(net "M_A_CPU0_SB_DQS_DP<6>")
	)
	(segment
		(start 319.063878 -221.357952)
		(end 319.063878 -221.533974)
		(width 0.20066)
		(layer "F.Cu")
		(net "M_A_CPU0_SB_DQS_DP<6>")
	)
	(segment
		(start 317.009018 -219.303092)
		(end 317.009018 -219.479114)
		(width 0.20066)
		(layer "F.Cu")
		(net "M_A_CPU0_SB_DQS_DP<6>")
	)
	(segment
		(start 319.489328 -225.727514)
		(end 319.613788 -225.851974)
		(width 0.20066)
		(layer "F.Cu")
		(net "M_A_CPU0_SB_DQS_DP<6>")
	)
	(segment
		(start 334.570832 -235.506006)
		(end 334.675734 -235.506006)
		(width 0.088646)
		(layer "F.Cu")
		(net "M_A_CPU0_SB_DQS_DP<6>")
	)
	(segment
		(start 334.007968 -235.010198)
		(end 334.368648 -235.190538)
		(width 0.088646)
		(layer "F.Cu")
		(net "M_A_CPU0_SB_DQS_DP<6>")
	)
	(segment
		(start 310.386984 -217.2843)
		(end 310.669686 -217.567002)
		(width 0.20066)
		(layer "F.Cu")
		(net "M_A_CPU0_SB_DQS_DP<6>")
	)
	(segment
		(start 315.350652 -218.09583)
		(end 315.820298 -218.290394)
		(width 0.20066)
		(layer "F.Cu")
		(net "M_A_CPU0_SB_DQS_DP<6>")
	)
	(segment
		(start 313.973464 -217.908632)
		(end 313.973464 -218.113356)
		(width 0.20066)
		(layer "F.Cu")
		(net "M_A_CPU0_SB_DQS_DP<6>")
	)
	(segment
		(start 306.406804 -217.977974)
		(end 306.833524 -217.551254)
		(width 0.20066)
		(layer "F.Cu")
		(net "M_A_CPU0_SB_DQS_DP<6>")
	)
	(segment
		(start 324.17131 -228.624638)
		(end 324.20941 -228.624638)
		(width 0.1524)
		(layer "F.Cu")
		(net "M_A_CPU0_SB_DQS_DP<6>")
	)
	(segment
		(start 307.768244 -217.291666)
		(end 310.068976 -217.291666)
		(width 0.1016)
		(layer "F.Cu")
		(net "M_A_CPU0_SB_DQS_DP<6>")
	)
	(segment
		(start 322.11645 -228.624638)
		(end 322.71843 -228.624638)
		(width 0.20066)
		(layer "F.Cu")
		(net "M_A_CPU0_SB_DQS_DP<6>")
	)
	(segment
		(start 311.07126 -217.567002)
		(end 311.714388 -217.99677)
		(width 0.20066)
		(layer "F.Cu")
		(net "M_A_CPU0_SB_DQS_DP<6>")
	)
	(segment
		(start 307.372258 -217.286332)
		(end 307.76291 -217.286332)
		(width 0.20066)
		(layer "F.Cu")
		(net "M_A_CPU0_SB_DQS_DP<6>")
	)
	(segment
		(start 318.63792 -220.931994)
		(end 319.063878 -221.357952)
		(width 0.20066)
		(layer "F.Cu")
		(net "M_A_CPU0_SB_DQS_DP<6>")
	)
	(segment
		(start 307.107336 -217.551254)
		(end 307.372258 -217.286332)
		(width 0.20066)
		(layer "F.Cu")
		(net "M_A_CPU0_SB_DQS_DP<6>")
	)
	(segment
		(start 319.613788 -225.001074)
		(end 319.489328 -225.125534)
		(width 0.20066)
		(layer "F.Cu")
		(net "M_A_CPU0_SB_DQS_DP<6>")
	)
	(segment
		(start 315.820298 -218.290394)
		(end 316.407038 -218.877134)
		(width 0.20066)
		(layer "F.Cu")
		(net "M_A_CPU0_SB_DQS_DP<6>")
	)
	(segment
		(start 313.973464 -218.113356)
		(end 314.095892 -218.235784)
		(width 0.20066)
		(layer "F.Cu")
		(net "M_A_CPU0_SB_DQS_DP<6>")
	)
	(segment
		(start 322.71843 -228.624638)
		(end 322.84289 -228.500178)
		(width 0.20066)
		(layer "F.Cu")
		(net "M_A_CPU0_SB_DQS_DP<6>")
	)
	(segment
		(start 319.489328 -223.672654)
		(end 319.489328 -224.274634)
		(width 0.20066)
		(layer "F.Cu")
		(net "M_A_CPU0_SB_DQS_DP<6>")
	)
	(segment
		(start 321.99199 -228.500178)
		(end 322.11645 -228.624638)
		(width 0.20066)
		(layer "F.Cu")
		(net "M_A_CPU0_SB_DQS_DP<6>")
	)
	(segment
		(start 324.70217 -228.661468)
		(end 330.860654 -234.819952)
		(width 0.1524)
		(layer "F.Cu")
		(net "M_A_CPU0_SB_DQS_DP<6>")
	)
	(segment
		(start 312.987182 -217.716608)
		(end 313.78144 -217.716608)
		(width 0.20066)
		(layer "F.Cu")
		(net "M_A_CPU0_SB_DQS_DP<6>")
	)
	(segment
		(start 321.074542 -228.624638)
		(end 321.26555 -228.624638)
		(width 0.20066)
		(layer "F.Cu")
		(net "M_A_CPU0_SB_DQS_DP<6>")
	)
	(segment
		(start 319.613788 -224.399094)
		(end 319.613788 -225.001074)
		(width 0.20066)
		(layer "F.Cu")
		(net "M_A_CPU0_SB_DQS_DP<6>")
	)
	(segment
		(start 305.443382 -217.716608)
		(end 305.917854 -217.716608)
		(width 0.20066)
		(layer "F.Cu")
		(net "M_A_CPU0_SB_DQS_DP<6>")
	)
	(segment
		(start 319.613788 -223.548194)
		(end 319.489328 -223.672654)
		(width 0.20066)
		(layer "F.Cu")
		(net "M_A_CPU0_SB_DQS_DP<6>")
	)
	(segment
		(start 331.992224 -234.940856)
		(end 332.796642 -234.940856)
		(width 0.088646)
		(layer "F.Cu")
		(net "M_A_CPU0_SB_DQS_DP<6>")
	)
	(segment
		(start 317.009018 -219.479114)
		(end 317.434468 -219.904564)
		(width 0.20066)
		(layer "F.Cu")
		(net "M_A_CPU0_SB_DQS_DP<6>")
	)
	(segment
		(start 331.90307 -234.851702)
		(end 331.992224 -234.940856)
		(width 0.088646)
		(layer "F.Cu")
		(net "M_A_CPU0_SB_DQS_DP<6>")
	)
	(segment
		(start 319.489328 -224.274634)
		(end 319.613788 -224.399094)
		(width 0.20066)
		(layer "F.Cu")
		(net "M_A_CPU0_SB_DQS_DP<6>")
	)
	(segment
		(start 320.223134 -227.597208)
		(end 320.649092 -228.023166)
		(width 0.20066)
		(layer "F.Cu")
		(net "M_A_CPU0_SB_DQS_DP<6>")
	)
	(segment
		(start 311.714388 -217.99677)
		(end 312.227468 -217.99677)
		(width 0.20066)
		(layer "F.Cu")
		(net "M_A_CPU0_SB_DQS_DP<6>")
	)
	(arc
		(start 332.796642 -234.940856)
		(mid 332.814557 -234.941084)
		(end 332.832456 -234.941872)
		(width 0.088646)
		(layer "F.Cu")
		(net "M_A_CPU0_SB_DQS_DP<6>")
	)
	(arc
		(start 333.091028 -235.024168)
		(mid 333.265071 -235.067235)
		(end 333.439262 -235.024676)
		(width 0.088646)
		(layer "F.Cu")
		(net "M_A_CPU0_SB_DQS_DP<6>")
	)
	(arc
		(start 333.453232 -235.016548)
		(mid 333.729761 -234.940681)
		(end 334.007968 -235.010198)
		(width 0.088646)
		(layer "F.Cu")
		(net "M_A_CPU0_SB_DQS_DP<6>")
	)
	(arc
		(start 332.832456 -234.941872)
		(mid 332.960249 -234.965182)
		(end 333.079344 -235.017056)
		(width 0.088646)
		(layer "F.Cu")
		(net "M_A_CPU0_SB_DQS_DP<6>")
	)
	(segment
		(start 338.904834 -237.9472)
		(end 338.904834 -237.411514)
		(width 0.20066)
		(layer "F.Cu")
		(net "M_A_CPU0_SB_DQS_DP<5>")
	)
	(segment
		(start 338.90458 -237.947454)
		(end 338.904834 -237.9472)
		(width 0.20066)
		(layer "F.Cu")
		(net "M_A_CPU0_SB_DQS_DP<5>")
	)
	(segment
		(start 305.917854 -227.066602)
		(end 305.443382 -227.066602)
		(width 0.20066)
		(layer "F.Cu")
		(net "M_A_CPU0_SB_DQS_DP<5>")
	)
	(segment
		(start 306.513484 -227.327968)
		(end 306.17922 -227.327968)
		(width 0.20066)
		(layer "F.Cu")
		(net "M_A_CPU0_SB_DQS_DP<5>")
	)
	(segment
		(start 310.087772 -226.64166)
		(end 307.833522 -226.64166)
		(width 0.1016)
		(layer "F.Cu")
		(net "M_A_CPU0_SB_DQS_DP<5>")
	)
	(segment
		(start 310.49722 -226.927918)
		(end 310.211216 -226.641914)
		(width 0.20066)
		(layer "F.Cu")
		(net "M_A_CPU0_SB_DQS_DP<5>")
	)
	(segment
		(start 312.50763 -227.066602)
		(end 312.246264 -227.327968)
		(width 0.20066)
		(layer "F.Cu")
		(net "M_A_CPU0_SB_DQS_DP<5>")
	)
	(segment
		(start 311.728866 -227.327968)
		(end 311.129934 -226.927918)
		(width 0.20066)
		(layer "F.Cu")
		(net "M_A_CPU0_SB_DQS_DP<5>")
	)
	(segment
		(start 312.246264 -227.327968)
		(end 311.728866 -227.327968)
		(width 0.20066)
		(layer "F.Cu")
		(net "M_A_CPU0_SB_DQS_DP<5>")
	)
	(segment
		(start 307.295296 -226.908868)
		(end 306.932584 -226.908868)
		(width 0.20066)
		(layer "F.Cu")
		(net "M_A_CPU0_SB_DQS_DP<5>")
	)
	(segment
		(start 307.784754 -226.63023)
		(end 307.76291 -226.63023)
		(width 0.101854)
		(layer "F.Cu")
		(net "M_A_CPU0_SB_DQS_DP<5>")
	)
	(segment
		(start 310.088026 -226.641914)
		(end 310.087772 -226.64166)
		(width 0.1016)
		(layer "F.Cu")
		(net "M_A_CPU0_SB_DQS_DP<5>")
	)
	(segment
		(start 314.092082 -227.066602)
		(end 312.987182 -227.066602)
		(width 0.20066)
		(layer "F.Cu")
		(net "M_A_CPU0_SB_DQS_DP<5>")
	)
	(segment
		(start 306.932584 -226.908868)
		(end 306.513484 -227.327968)
		(width 0.20066)
		(layer "F.Cu")
		(net "M_A_CPU0_SB_DQS_DP<5>")
	)
	(segment
		(start 312.987182 -227.066602)
		(end 312.50763 -227.066602)
		(width 0.20066)
		(layer "F.Cu")
		(net "M_A_CPU0_SB_DQS_DP<5>")
	)
	(segment
		(start 311.129934 -226.927918)
		(end 310.49722 -226.927918)
		(width 0.20066)
		(layer "F.Cu")
		(net "M_A_CPU0_SB_DQS_DP<5>")
	)
	(segment
		(start 307.833522 -226.64166)
		(end 307.784754 -226.63023)
		(width 0.1016)
		(layer "F.Cu")
		(net "M_A_CPU0_SB_DQS_DP<5>")
	)
	(segment
		(start 307.76291 -226.63023)
		(end 307.573934 -226.63023)
		(width 0.20066)
		(layer "F.Cu")
		(net "M_A_CPU0_SB_DQS_DP<5>")
	)
	(segment
		(start 306.17922 -227.327968)
		(end 305.917854 -227.066602)
		(width 0.20066)
		(layer "F.Cu")
		(net "M_A_CPU0_SB_DQS_DP<5>")
	)
	(segment
		(start 310.211216 -226.641914)
		(end 310.088026 -226.641914)
		(width 0.20066)
		(layer "F.Cu")
		(net "M_A_CPU0_SB_DQS_DP<5>")
	)
	(segment
		(start 307.573934 -226.63023)
		(end 307.295296 -226.908868)
		(width 0.20066)
		(layer "F.Cu")
		(net "M_A_CPU0_SB_DQS_DP<5>")
	)
	(segment
		(start 318.671448 -227.344732)
		(end 314.370212 -227.344732)
		(width 0.18288)
		(layer "In2.Cu")
		(net "M_A_CPU0_SB_DQS_DP<5>")
	)
	(segment
		(start 328.237596 -236.917992)
		(end 318.667892 -227.348288)
		(width 0.18288)
		(layer "In2.Cu")
		(net "M_A_CPU0_SB_DQS_DP<5>")
	)
	(segment
		(start 335.802732 -236.922056)
		(end 335.79181 -236.928406)
		(width 0.088646)
		(layer "In2.Cu")
		(net "M_A_CPU0_SB_DQS_DP<5>")
	)
	(segment
		(start 338.904834 -237.411514)
		(end 338.591906 -237.411514)
		(width 0.088646)
		(layer "In2.Cu")
		(net "M_A_CPU0_SB_DQS_DP<5>")
	)
	(segment
		(start 338.253578 -236.925612)
		(end 338.247482 -236.922056)
		(width 0.088646)
		(layer "In2.Cu")
		(net "M_A_CPU0_SB_DQS_DP<5>")
	)
	(segment
		(start 331.795628 -236.977936)
		(end 330.792582 -236.977936)
		(width 0.088646)
		(layer "In2.Cu")
		(net "M_A_CPU0_SB_DQS_DP<5>")
	)
	(segment
		(start 318.667892 -227.348288)
		(end 318.671448 -227.344732)
		(width 0.18288)
		(layer "In2.Cu")
		(net "M_A_CPU0_SB_DQS_DP<5>")
	)
	(segment
		(start 314.370212 -227.344732)
		(end 314.092082 -227.066602)
		(width 0.18288)
		(layer "In2.Cu")
		(net "M_A_CPU0_SB_DQS_DP<5>")
	)
	(segment
		(start 330.792582 -236.977936)
		(end 330.732638 -236.917992)
		(width 0.088646)
		(layer "In2.Cu")
		(net "M_A_CPU0_SB_DQS_DP<5>")
	)
	(segment
		(start 330.732638 -236.917992)
		(end 328.237596 -236.917992)
		(width 0.18288)
		(layer "In2.Cu")
		(net "M_A_CPU0_SB_DQS_DP<5>")
	)
	(segment
		(start 338.247482 -236.922056)
		(end 338.23275 -236.91342)
		(width 0.088646)
		(layer "In2.Cu")
		(net "M_A_CPU0_SB_DQS_DP<5>")
	)
	(segment
		(start 332.998064 -236.913674)
		(end 332.983332 -236.92231)
		(width 0.088646)
		(layer "In2.Cu")
		(net "M_A_CPU0_SB_DQS_DP<5>")
	)
	(segment
		(start 338.591906 -237.411514)
		(end 338.526374 -237.345982)
		(width 0.088646)
		(layer "In2.Cu")
		(net "M_A_CPU0_SB_DQS_DP<5>")
	)
	(segment
		(start 334.877664 -236.913674)
		(end 334.862932 -236.92231)
		(width 0.088646)
		(layer "In2.Cu")
		(net "M_A_CPU0_SB_DQS_DP<5>")
	)
	(segment
		(start 337.307682 -236.922056)
		(end 337.297268 -236.91596)
		(width 0.088646)
		(layer "In2.Cu")
		(net "M_A_CPU0_SB_DQS_DP<5>")
	)
	(arc
		(start 332.060296 -236.91215)
		(mid 331.931991 -236.961255)
		(end 331.795628 -236.977936)
		(width 0.088646)
		(layer "In2.Cu")
		(net "M_A_CPU0_SB_DQS_DP<5>")
	)
	(arc
		(start 334.862932 -236.92231)
		(mid 334.675734 -236.972453)
		(end 334.488536 -236.92231)
		(width 0.088646)
		(layer "In2.Cu")
		(net "M_A_CPU0_SB_DQS_DP<5>")
	)
	(arc
		(start 338.526374 -237.345982)
		(mid 338.43913 -237.103894)
		(end 338.253578 -236.925612)
		(width 0.088646)
		(layer "In2.Cu")
		(net "M_A_CPU0_SB_DQS_DP<5>")
	)
	(arc
		(start 332.608936 -236.92231)
		(mid 332.425032 -236.855068)
		(end 332.229206 -236.854492)
		(width 0.088646)
		(layer "In2.Cu")
		(net "M_A_CPU0_SB_DQS_DP<5>")
	)
	(arc
		(start 332.229206 -236.854492)
		(mid 332.142455 -236.876599)
		(end 332.060296 -236.91215)
		(width 0.088646)
		(layer "In2.Cu")
		(net "M_A_CPU0_SB_DQS_DP<5>")
	)
	(arc
		(start 337.682078 -236.922056)
		(mid 337.49488 -236.972233)
		(end 337.307682 -236.922056)
		(width 0.088646)
		(layer "In2.Cu")
		(net "M_A_CPU0_SB_DQS_DP<5>")
	)
	(arc
		(start 335.79181 -236.928406)
		(mid 335.60928 -236.97243)
		(end 335.428336 -236.92231)
		(width 0.088646)
		(layer "In2.Cu")
		(net "M_A_CPU0_SB_DQS_DP<5>")
	)
	(arc
		(start 336.368136 -236.922056)
		(mid 336.085434 -236.84628)
		(end 335.802732 -236.922056)
		(width 0.088646)
		(layer "In2.Cu")
		(net "M_A_CPU0_SB_DQS_DP<5>")
	)
	(arc
		(start 336.742532 -236.922056)
		(mid 336.555334 -236.972233)
		(end 336.368136 -236.922056)
		(width 0.088646)
		(layer "In2.Cu")
		(net "M_A_CPU0_SB_DQS_DP<5>")
	)
	(arc
		(start 333.548736 -236.92231)
		(mid 333.274537 -236.846475)
		(end 332.998064 -236.913674)
		(width 0.088646)
		(layer "In2.Cu")
		(net "M_A_CPU0_SB_DQS_DP<5>")
	)
	(arc
		(start 332.983332 -236.92231)
		(mid 332.796134 -236.972453)
		(end 332.608936 -236.92231)
		(width 0.088646)
		(layer "In2.Cu")
		(net "M_A_CPU0_SB_DQS_DP<5>")
	)
	(arc
		(start 334.488536 -236.92231)
		(mid 334.205834 -236.846534)
		(end 333.923132 -236.92231)
		(width 0.088646)
		(layer "In2.Cu")
		(net "M_A_CPU0_SB_DQS_DP<5>")
	)
	(arc
		(start 338.23275 -236.91342)
		(mid 337.956275 -236.8461)
		(end 337.682078 -236.922056)
		(width 0.088646)
		(layer "In2.Cu")
		(net "M_A_CPU0_SB_DQS_DP<5>")
	)
	(arc
		(start 337.297268 -236.91596)
		(mid 337.01909 -236.846237)
		(end 336.742532 -236.922056)
		(width 0.088646)
		(layer "In2.Cu")
		(net "M_A_CPU0_SB_DQS_DP<5>")
	)
	(arc
		(start 335.428336 -236.92231)
		(mid 335.154137 -236.846475)
		(end 334.877664 -236.913674)
		(width 0.088646)
		(layer "In2.Cu")
		(net "M_A_CPU0_SB_DQS_DP<5>")
	)
	(arc
		(start 333.923132 -236.92231)
		(mid 333.735934 -236.972453)
		(end 333.548736 -236.92231)
		(width 0.088646)
		(layer "In2.Cu")
		(net "M_A_CPU0_SB_DQS_DP<5>")
	)
	(segment
		(start 313.803538 -236.416596)
		(end 313.995816 -236.608874)
		(width 0.20066)
		(layer "F.Cu")
		(net "M_A_CPU0_SB_DQS_DP<4>")
	)
	(segment
		(start 330.920598 -239.05083)
		(end 331.262228 -239.39246)
		(width 0.1524)
		(layer "F.Cu")
		(net "M_A_CPU0_SB_DQS_DP<4>")
	)
	(segment
		(start 314.83681 -236.785404)
		(end 315.43879 -236.785404)
		(width 0.20066)
		(layer "F.Cu")
		(net "M_A_CPU0_SB_DQS_DP<4>")
	)
	(segment
		(start 323.774054 -239.014)
		(end 324.562724 -239.014)
		(width 0.20066)
		(layer "F.Cu")
		(net "M_A_CPU0_SB_DQS_DP<4>")
	)
	(segment
		(start 307.302916 -236.251242)
		(end 307.562504 -235.991654)
		(width 0.20066)
		(layer "F.Cu")
		(net "M_A_CPU0_SB_DQS_DP<4>")
	)
	(segment
		(start 324.687184 -238.88954)
		(end 325.289164 -238.88954)
		(width 0.20066)
		(layer "F.Cu")
		(net "M_A_CPU0_SB_DQS_DP<4>")
	)
	(segment
		(start 319.326006 -237.244128)
		(end 319.450466 -237.368588)
		(width 0.20066)
		(layer "F.Cu")
		(net "M_A_CPU0_SB_DQS_DP<4>")
	)
	(segment
		(start 334.006952 -239.89284)
		(end 334.00746 -239.893348)
		(width 0.088646)
		(layer "F.Cu")
		(net "M_A_CPU0_SB_DQS_DP<4>")
	)
	(segment
		(start 317.271146 -237.244128)
		(end 317.873126 -237.244128)
		(width 0.20066)
		(layer "F.Cu")
		(net "M_A_CPU0_SB_DQS_DP<4>")
	)
	(segment
		(start 332.053438 -239.824006)
		(end 332.796388 -239.824006)
		(width 0.088646)
		(layer "F.Cu")
		(net "M_A_CPU0_SB_DQS_DP<4>")
	)
	(segment
		(start 306.513484 -236.677962)
		(end 306.843176 -236.34827)
		(width 0.20066)
		(layer "F.Cu")
		(net "M_A_CPU0_SB_DQS_DP<4>")
	)
	(segment
		(start 312.987182 -236.416596)
		(end 313.803538 -236.416596)
		(width 0.20066)
		(layer "F.Cu")
		(net "M_A_CPU0_SB_DQS_DP<4>")
	)
	(segment
		(start 317.873126 -237.244128)
		(end 317.997586 -237.368588)
		(width 0.20066)
		(layer "F.Cu")
		(net "M_A_CPU0_SB_DQS_DP<4>")
	)
	(segment
		(start 319.750948 -237.368588)
		(end 320.306954 -237.598712)
		(width 0.20066)
		(layer "F.Cu")
		(net "M_A_CPU0_SB_DQS_DP<4>")
	)
	(segment
		(start 311.806336 -236.677962)
		(end 312.246264 -236.677962)
		(width 0.20066)
		(layer "F.Cu")
		(net "M_A_CPU0_SB_DQS_DP<4>")
	)
	(segment
		(start 321.026028 -237.762034)
		(end 321.093338 -237.924594)
		(width 0.20066)
		(layer "F.Cu")
		(net "M_A_CPU0_SB_DQS_DP<4>")
	)
	(segment
		(start 331.277722 -239.452658)
		(end 331.443584 -239.618774)
		(width 0.088646)
		(layer "F.Cu")
		(net "M_A_CPU0_SB_DQS_DP<4>")
	)
	(segment
		(start 327.592944 -238.88954)
		(end 328.194924 -238.88954)
		(width 0.20066)
		(layer "F.Cu")
		(net "M_A_CPU0_SB_DQS_DP<4>")
	)
	(segment
		(start 331.443584 -239.618774)
		(end 331.600556 -239.618774)
		(width 0.088646)
		(layer "F.Cu")
		(net "M_A_CPU0_SB_DQS_DP<4>")
	)
	(segment
		(start 331.277722 -239.407954)
		(end 331.277722 -239.452658)
		(width 0.088646)
		(layer "F.Cu")
		(net "M_A_CPU0_SB_DQS_DP<4>")
	)
	(segment
		(start 319.450466 -237.368588)
		(end 319.750948 -237.368588)
		(width 0.20066)
		(layer "F.Cu")
		(net "M_A_CPU0_SB_DQS_DP<4>")
	)
	(segment
		(start 333.078582 -239.899952)
		(end 333.078582 -239.899698)
		(width 0.088646)
		(layer "F.Cu")
		(net "M_A_CPU0_SB_DQS_DP<4>")
	)
	(segment
		(start 315.56325 -236.909864)
		(end 316.085982 -236.909864)
		(width 0.20066)
		(layer "F.Cu")
		(net "M_A_CPU0_SB_DQS_DP<4>")
	)
	(segment
		(start 323.64299 -237.712758)
		(end 323.64299 -238.882936)
		(width 0.20066)
		(layer "F.Cu")
		(net "M_A_CPU0_SB_DQS_DP<4>")
	)
	(segment
		(start 323.64299 -238.882936)
		(end 323.774054 -239.014)
		(width 0.20066)
		(layer "F.Cu")
		(net "M_A_CPU0_SB_DQS_DP<4>")
	)
	(segment
		(start 321.093338 -237.924594)
		(end 321.815714 -238.223806)
		(width 0.20066)
		(layer "F.Cu")
		(net "M_A_CPU0_SB_DQS_DP<4>")
	)
	(segment
		(start 326.742044 -238.88954)
		(end 326.866504 -239.014)
		(width 0.20066)
		(layer "F.Cu")
		(net "M_A_CPU0_SB_DQS_DP<4>")
	)
	(segment
		(start 327.468484 -239.014)
		(end 327.592944 -238.88954)
		(width 0.20066)
		(layer "F.Cu")
		(net "M_A_CPU0_SB_DQS_DP<4>")
	)
	(segment
		(start 311.173876 -236.255306)
		(end 311.806336 -236.677962)
		(width 0.20066)
		(layer "F.Cu")
		(net "M_A_CPU0_SB_DQS_DP<4>")
	)
	(segment
		(start 318.724026 -237.244128)
		(end 319.326006 -237.244128)
		(width 0.20066)
		(layer "F.Cu")
		(net "M_A_CPU0_SB_DQS_DP<4>")
	)
	(segment
		(start 328.194924 -238.88954)
		(end 328.319384 -239.014)
		(width 0.20066)
		(layer "F.Cu")
		(net "M_A_CPU0_SB_DQS_DP<4>")
	)
	(segment
		(start 317.146686 -237.368588)
		(end 317.271146 -237.244128)
		(width 0.20066)
		(layer "F.Cu")
		(net "M_A_CPU0_SB_DQS_DP<4>")
	)
	(segment
		(start 334.00746 -239.893348)
		(end 334.368394 -240.073688)
		(width 0.088646)
		(layer "F.Cu")
		(net "M_A_CPU0_SB_DQS_DP<4>")
	)
	(segment
		(start 305.917854 -236.416596)
		(end 306.17922 -236.677962)
		(width 0.20066)
		(layer "F.Cu")
		(net "M_A_CPU0_SB_DQS_DP<4>")
	)
	(segment
		(start 331.262228 -239.39246)
		(end 331.277722 -239.407954)
		(width 0.088646)
		(layer "F.Cu")
		(net "M_A_CPU0_SB_DQS_DP<4>")
	)
	(segment
		(start 328.996294 -239.05083)
		(end 330.920598 -239.05083)
		(width 0.1524)
		(layer "F.Cu")
		(net "M_A_CPU0_SB_DQS_DP<4>")
	)
	(segment
		(start 314.11037 -236.909864)
		(end 314.71235 -236.909864)
		(width 0.20066)
		(layer "F.Cu")
		(net "M_A_CPU0_SB_DQS_DP<4>")
	)
	(segment
		(start 312.246264 -236.677962)
		(end 312.50763 -236.416596)
		(width 0.20066)
		(layer "F.Cu")
		(net "M_A_CPU0_SB_DQS_DP<4>")
	)
	(segment
		(start 326.140064 -238.88954)
		(end 326.742044 -238.88954)
		(width 0.20066)
		(layer "F.Cu")
		(net "M_A_CPU0_SB_DQS_DP<4>")
	)
	(segment
		(start 306.843176 -236.34827)
		(end 307.077618 -236.251242)
		(width 0.20066)
		(layer "F.Cu")
		(net "M_A_CPU0_SB_DQS_DP<4>")
	)
	(segment
		(start 307.638958 -235.991654)
		(end 310.34482 -235.991654)
		(width 0.1016)
		(layer "F.Cu")
		(net "M_A_CPU0_SB_DQS_DP<4>")
	)
	(segment
		(start 316.544706 -237.368588)
		(end 317.146686 -237.368588)
		(width 0.20066)
		(layer "F.Cu")
		(net "M_A_CPU0_SB_DQS_DP<4>")
	)
	(segment
		(start 322.269612 -237.712758)
		(end 322.662296 -237.320074)
		(width 0.20066)
		(layer "F.Cu")
		(net "M_A_CPU0_SB_DQS_DP<4>")
	)
	(segment
		(start 328.959464 -239.014)
		(end 328.996294 -239.05083)
		(width 0.1524)
		(layer "F.Cu")
		(net "M_A_CPU0_SB_DQS_DP<4>")
	)
	(segment
		(start 322.662296 -237.320074)
		(end 323.250306 -237.320074)
		(width 0.20066)
		(layer "F.Cu")
		(net "M_A_CPU0_SB_DQS_DP<4>")
	)
	(segment
		(start 328.319384 -239.014)
		(end 328.921364 -239.014)
		(width 0.20066)
		(layer "F.Cu")
		(net "M_A_CPU0_SB_DQS_DP<4>")
	)
	(segment
		(start 318.599566 -237.368588)
		(end 318.724026 -237.244128)
		(width 0.20066)
		(layer "F.Cu")
		(net "M_A_CPU0_SB_DQS_DP<4>")
	)
	(segment
		(start 312.50763 -236.416596)
		(end 312.987182 -236.416596)
		(width 0.20066)
		(layer "F.Cu")
		(net "M_A_CPU0_SB_DQS_DP<4>")
	)
	(segment
		(start 313.995816 -236.79531)
		(end 314.11037 -236.909864)
		(width 0.20066)
		(layer "F.Cu")
		(net "M_A_CPU0_SB_DQS_DP<4>")
	)
	(segment
		(start 310.445658 -235.991654)
		(end 310.70931 -236.255306)
		(width 0.20066)
		(layer "F.Cu")
		(net "M_A_CPU0_SB_DQS_DP<4>")
	)
	(segment
		(start 320.306954 -237.598712)
		(end 320.469514 -237.531402)
		(width 0.20066)
		(layer "F.Cu")
		(net "M_A_CPU0_SB_DQS_DP<4>")
	)
	(segment
		(start 321.815714 -238.223806)
		(end 322.162932 -238.223806)
		(width 0.20066)
		(layer "F.Cu")
		(net "M_A_CPU0_SB_DQS_DP<4>")
	)
	(segment
		(start 334.486504 -240.304828)
		(end 334.570832 -240.389156)
		(width 0.088646)
		(layer "F.Cu")
		(net "M_A_CPU0_SB_DQS_DP<4>")
	)
	(segment
		(start 325.289164 -238.88954)
		(end 325.413624 -239.014)
		(width 0.20066)
		(layer "F.Cu")
		(net "M_A_CPU0_SB_DQS_DP<4>")
	)
	(segment
		(start 315.43879 -236.785404)
		(end 315.56325 -236.909864)
		(width 0.20066)
		(layer "F.Cu")
		(net "M_A_CPU0_SB_DQS_DP<4>")
	)
	(segment
		(start 317.997586 -237.368588)
		(end 318.599566 -237.368588)
		(width 0.20066)
		(layer "F.Cu")
		(net "M_A_CPU0_SB_DQS_DP<4>")
	)
	(segment
		(start 322.269612 -238.117126)
		(end 322.269612 -237.712758)
		(width 0.20066)
		(layer "F.Cu")
		(net "M_A_CPU0_SB_DQS_DP<4>")
	)
	(segment
		(start 307.077618 -236.251242)
		(end 307.302916 -236.251242)
		(width 0.20066)
		(layer "F.Cu")
		(net "M_A_CPU0_SB_DQS_DP<4>")
	)
	(segment
		(start 323.250306 -237.320074)
		(end 323.64299 -237.712758)
		(width 0.20066)
		(layer "F.Cu")
		(net "M_A_CPU0_SB_DQS_DP<4>")
	)
	(segment
		(start 314.71235 -236.909864)
		(end 314.83681 -236.785404)
		(width 0.20066)
		(layer "F.Cu")
		(net "M_A_CPU0_SB_DQS_DP<4>")
	)
	(segment
		(start 316.085982 -236.909864)
		(end 316.544706 -237.368588)
		(width 0.20066)
		(layer "F.Cu")
		(net "M_A_CPU0_SB_DQS_DP<4>")
	)
	(segment
		(start 305.443382 -236.416596)
		(end 305.917854 -236.416596)
		(width 0.20066)
		(layer "F.Cu")
		(net "M_A_CPU0_SB_DQS_DP<4>")
	)
	(segment
		(start 313.995816 -236.608874)
		(end 313.995816 -236.79531)
		(width 0.20066)
		(layer "F.Cu")
		(net "M_A_CPU0_SB_DQS_DP<4>")
	)
	(segment
		(start 328.921364 -239.014)
		(end 328.959464 -239.014)
		(width 0.1524)
		(layer "F.Cu")
		(net "M_A_CPU0_SB_DQS_DP<4>")
	)
	(segment
		(start 326.866504 -239.014)
		(end 327.468484 -239.014)
		(width 0.20066)
		(layer "F.Cu")
		(net "M_A_CPU0_SB_DQS_DP<4>")
	)
	(segment
		(start 334.368394 -240.073688)
		(end 334.486504 -240.304828)
		(width 0.088646)
		(layer "F.Cu")
		(net "M_A_CPU0_SB_DQS_DP<4>")
	)
	(segment
		(start 322.162932 -238.223806)
		(end 322.269612 -238.117126)
		(width 0.20066)
		(layer "F.Cu")
		(net "M_A_CPU0_SB_DQS_DP<4>")
	)
	(segment
		(start 320.469514 -237.531402)
		(end 321.026028 -237.762034)
		(width 0.20066)
		(layer "F.Cu")
		(net "M_A_CPU0_SB_DQS_DP<4>")
	)
	(segment
		(start 334.570832 -240.389156)
		(end 334.675734 -240.389156)
		(width 0.088646)
		(layer "F.Cu")
		(net "M_A_CPU0_SB_DQS_DP<4>")
	)
	(segment
		(start 331.600556 -239.618774)
		(end 331.752194 -239.770158)
		(width 0.088646)
		(layer "F.Cu")
		(net "M_A_CPU0_SB_DQS_DP<4>")
	)
	(segment
		(start 324.562724 -239.014)
		(end 324.687184 -238.88954)
		(width 0.20066)
		(layer "F.Cu")
		(net "M_A_CPU0_SB_DQS_DP<4>")
	)
	(segment
		(start 310.70931 -236.255306)
		(end 311.173876 -236.255306)
		(width 0.20066)
		(layer "F.Cu")
		(net "M_A_CPU0_SB_DQS_DP<4>")
	)
	(segment
		(start 325.413624 -239.014)
		(end 326.015604 -239.014)
		(width 0.20066)
		(layer "F.Cu")
		(net "M_A_CPU0_SB_DQS_DP<4>")
	)
	(segment
		(start 326.015604 -239.014)
		(end 326.140064 -238.88954)
		(width 0.20066)
		(layer "F.Cu")
		(net "M_A_CPU0_SB_DQS_DP<4>")
	)
	(segment
		(start 307.562504 -235.991654)
		(end 307.638958 -235.991654)
		(width 0.20066)
		(layer "F.Cu")
		(net "M_A_CPU0_SB_DQS_DP<4>")
	)
	(segment
		(start 310.34482 -235.991654)
		(end 310.445658 -235.991654)
		(width 0.20066)
		(layer "F.Cu")
		(net "M_A_CPU0_SB_DQS_DP<4>")
	)
	(segment
		(start 306.17922 -236.677962)
		(end 306.513484 -236.677962)
		(width 0.20066)
		(layer "F.Cu")
		(net "M_A_CPU0_SB_DQS_DP<4>")
	)
	(arc
		(start 331.752194 -239.770158)
		(mid 331.900441 -239.810363)
		(end 332.053438 -239.824006)
		(width 0.088646)
		(layer "F.Cu")
		(net "M_A_CPU0_SB_DQS_DP<4>")
	)
	(arc
		(start 333.452978 -239.899698)
		(mid 333.729082 -239.823712)
		(end 334.006952 -239.89284)
		(width 0.088646)
		(layer "F.Cu")
		(net "M_A_CPU0_SB_DQS_DP<4>")
	)
	(arc
		(start 333.078582 -239.899698)
		(mid 333.26578 -239.949841)
		(end 333.452978 -239.899698)
		(width 0.088646)
		(layer "F.Cu")
		(net "M_A_CPU0_SB_DQS_DP<4>")
	)
	(arc
		(start 332.796388 -239.824006)
		(mid 332.942476 -239.843427)
		(end 333.078582 -239.899952)
		(width 0.088646)
		(layer "F.Cu")
		(net "M_A_CPU0_SB_DQS_DP<4>")
	)
	(segment
		(start 303.672494 -200.887838)
		(end 303.932844 -201.148188)
		(width 0.20066)
		(layer "F.Cu")
		(net "M_A_CPU0_SB_DQS_DP<3>")
	)
	(segment
		(start 304.325528 -201.141838)
		(end 306.634388 -201.141838)
		(width 0.1016)
		(layer "F.Cu")
		(net "M_A_CPU0_SB_DQS_DP<3>")
	)
	(segment
		(start 306.936902 -201.153268)
		(end 307.203094 -200.887076)
		(width 0.20066)
		(layer "F.Cu")
		(net "M_A_CPU0_SB_DQS_DP<3>")
	)
	(segment
		(start 314.15228 -201.148188)
		(end 314.145676 -201.148188)
		(width 0.1016)
		(layer "F.Cu")
		(net "M_A_CPU0_SB_DQS_DP<3>")
	)
	(segment
		(start 306.644548 -201.151998)
		(end 306.645818 -201.153268)
		(width 0.20066)
		(layer "F.Cu")
		(net "M_A_CPU0_SB_DQS_DP<3>")
	)
	(segment
		(start 307.928264 -200.434956)
		(end 308.056788 -200.434956)
		(width 0.20066)
		(layer "F.Cu")
		(net "M_A_CPU0_SB_DQS_DP<3>")
	)
	(segment
		(start 309.381398 -200.716642)
		(end 308.887114 -200.716642)
		(width 0.20066)
		(layer "F.Cu")
		(net "M_A_CPU0_SB_DQS_DP<3>")
	)
	(segment
		(start 301.343314 -200.716642)
		(end 301.932594 -200.716642)
		(width 0.20066)
		(layer "F.Cu")
		(net "M_A_CPU0_SB_DQS_DP<3>")
	)
	(segment
		(start 303.932844 -201.148188)
		(end 304.319178 -201.148188)
		(width 0.20066)
		(layer "F.Cu")
		(net "M_A_CPU0_SB_DQS_DP<3>")
	)
	(segment
		(start 304.319178 -201.148188)
		(end 304.319432 -201.147934)
		(width 0.20066)
		(layer "F.Cu")
		(net "M_A_CPU0_SB_DQS_DP<3>")
	)
	(segment
		(start 301.932594 -200.716642)
		(end 302.184054 -200.465182)
		(width 0.20066)
		(layer "F.Cu")
		(net "M_A_CPU0_SB_DQS_DP<3>")
	)
	(segment
		(start 332.210918 -220.83649)
		(end 332.08595 -220.711522)
		(width 0.088646)
		(layer "F.Cu")
		(net "M_A_CPU0_SB_DQS_DP<3>")
	)
	(segment
		(start 331.310234 -219.981272)
		(end 331.29474 -219.965778)
		(width 0.088646)
		(layer "F.Cu")
		(net "M_A_CPU0_SB_DQS_DP<3>")
	)
	(segment
		(start 332.937104 -221.16288)
		(end 332.885288 -221.193106)
		(width 0.088646)
		(layer "F.Cu")
		(net "M_A_CPU0_SB_DQS_DP<3>")
	)
	(segment
		(start 333.735934 -220.855794)
		(end 333.696818 -220.840046)
		(width 0.088646)
		(layer "F.Cu")
		(net "M_A_CPU0_SB_DQS_DP<3>")
	)
	(segment
		(start 302.184054 -200.465182)
		(end 302.356266 -200.465182)
		(width 0.20066)
		(layer "F.Cu")
		(net "M_A_CPU0_SB_DQS_DP<3>")
	)
	(segment
		(start 333.696818 -220.840046)
		(end 332.937104 -221.16288)
		(width 0.088646)
		(layer "F.Cu")
		(net "M_A_CPU0_SB_DQS_DP<3>")
	)
	(segment
		(start 331.400404 -214.601298)
		(end 331.400404 -214.061548)
		(width 0.1524)
		(layer "F.Cu")
		(net "M_A_CPU0_SB_DQS_DP<3>")
	)
	(segment
		(start 321.932808 -200.899776)
		(end 314.549536 -200.899776)
		(width 0.20066)
		(layer "F.Cu")
		(net "M_A_CPU0_SB_DQS_DP<3>")
	)
	(segment
		(start 332.885288 -221.193106)
		(end 332.570074 -221.193106)
		(width 0.088646)
		(layer "F.Cu")
		(net "M_A_CPU0_SB_DQS_DP<3>")
	)
	(segment
		(start 330.585572 -215.41613)
		(end 331.400404 -214.601298)
		(width 0.1524)
		(layer "F.Cu")
		(net "M_A_CPU0_SB_DQS_DP<3>")
	)
	(segment
		(start 311.426606 -200.935336)
		(end 311.052464 -200.935336)
		(width 0.20066)
		(layer "F.Cu")
		(net "M_A_CPU0_SB_DQS_DP<3>")
	)
	(segment
		(start 311.427876 -200.934066)
		(end 311.426606 -200.935336)
		(width 0.20066)
		(layer "F.Cu")
		(net "M_A_CPU0_SB_DQS_DP<3>")
	)
	(segment
		(start 331.33919 -210.306158)
		(end 321.932808 -200.899776)
		(width 0.20066)
		(layer "F.Cu")
		(net "M_A_CPU0_SB_DQS_DP<3>")
	)
	(segment
		(start 311.956958 -201.141584)
		(end 311.94248 -201.156062)
		(width 0.1016)
		(layer "F.Cu")
		(net "M_A_CPU0_SB_DQS_DP<3>")
	)
	(segment
		(start 314.549536 -200.899776)
		(end 314.301124 -201.148188)
		(width 0.20066)
		(layer "F.Cu")
		(net "M_A_CPU0_SB_DQS_DP<3>")
	)
	(segment
		(start 309.869078 -200.445116)
		(end 309.652924 -200.445116)
		(width 0.20066)
		(layer "F.Cu")
		(net "M_A_CPU0_SB_DQS_DP<3>")
	)
	(segment
		(start 306.645818 -201.153268)
		(end 306.936902 -201.153268)
		(width 0.20066)
		(layer "F.Cu")
		(net "M_A_CPU0_SB_DQS_DP<3>")
	)
	(segment
		(start 303.37633 -200.887838)
		(end 303.672494 -200.887838)
		(width 0.20066)
		(layer "F.Cu")
		(net "M_A_CPU0_SB_DQS_DP<3>")
	)
	(segment
		(start 332.08595 -220.711522)
		(end 332.085696 -220.711522)
		(width 0.088646)
		(layer "F.Cu")
		(net "M_A_CPU0_SB_DQS_DP<3>")
	)
	(segment
		(start 309.652924 -200.445116)
		(end 309.381398 -200.716642)
		(width 0.20066)
		(layer "F.Cu")
		(net "M_A_CPU0_SB_DQS_DP<3>")
	)
	(segment
		(start 304.319432 -201.147934)
		(end 304.325528 -201.141838)
		(width 0.101854)
		(layer "F.Cu")
		(net "M_A_CPU0_SB_DQS_DP<3>")
	)
	(segment
		(start 330.585572 -219.25661)
		(end 330.585572 -215.41613)
		(width 0.1524)
		(layer "F.Cu")
		(net "M_A_CPU0_SB_DQS_DP<3>")
	)
	(segment
		(start 314.301124 -201.148188)
		(end 314.15228 -201.148188)
		(width 0.20066)
		(layer "F.Cu")
		(net "M_A_CPU0_SB_DQS_DP<3>")
	)
	(segment
		(start 332.085696 -220.711522)
		(end 331.355446 -219.981272)
		(width 0.088646)
		(layer "F.Cu")
		(net "M_A_CPU0_SB_DQS_DP<3>")
	)
	(segment
		(start 332.570074 -221.193106)
		(end 332.465426 -221.149926)
		(width 0.088646)
		(layer "F.Cu")
		(net "M_A_CPU0_SB_DQS_DP<3>")
	)
	(segment
		(start 306.634388 -201.141838)
		(end 306.644548 -201.151998)
		(width 0.101854)
		(layer "F.Cu")
		(net "M_A_CPU0_SB_DQS_DP<3>")
	)
	(segment
		(start 332.25232 -220.93682)
		(end 332.210918 -220.83649)
		(width 0.088646)
		(layer "F.Cu")
		(net "M_A_CPU0_SB_DQS_DP<3>")
	)
	(segment
		(start 314.139072 -201.141584)
		(end 311.956958 -201.141584)
		(width 0.1016)
		(layer "F.Cu")
		(net "M_A_CPU0_SB_DQS_DP<3>")
	)
	(segment
		(start 311.94248 -201.156062)
		(end 311.649872 -201.156062)
		(width 0.20066)
		(layer "F.Cu")
		(net "M_A_CPU0_SB_DQS_DP<3>")
	)
	(segment
		(start 308.056788 -200.434956)
		(end 308.338474 -200.716642)
		(width 0.20066)
		(layer "F.Cu")
		(net "M_A_CPU0_SB_DQS_DP<3>")
	)
	(segment
		(start 311.052464 -200.935336)
		(end 309.869078 -200.445116)
		(width 0.20066)
		(layer "F.Cu")
		(net "M_A_CPU0_SB_DQS_DP<3>")
	)
	(segment
		(start 331.372464 -214.033608)
		(end 331.372464 -210.386422)
		(width 0.20066)
		(layer "F.Cu")
		(net "M_A_CPU0_SB_DQS_DP<3>")
	)
	(segment
		(start 307.203094 -200.887076)
		(end 307.476144 -200.887076)
		(width 0.20066)
		(layer "F.Cu")
		(net "M_A_CPU0_SB_DQS_DP<3>")
	)
	(segment
		(start 331.29474 -219.965778)
		(end 330.585572 -219.25661)
		(width 0.1524)
		(layer "F.Cu")
		(net "M_A_CPU0_SB_DQS_DP<3>")
	)
	(segment
		(start 311.649872 -201.156062)
		(end 311.427876 -200.934066)
		(width 0.20066)
		(layer "F.Cu")
		(net "M_A_CPU0_SB_DQS_DP<3>")
	)
	(segment
		(start 331.400404 -214.061548)
		(end 331.372464 -214.033608)
		(width 0.1524)
		(layer "F.Cu")
		(net "M_A_CPU0_SB_DQS_DP<3>")
	)
	(segment
		(start 308.338474 -200.716642)
		(end 308.887114 -200.716642)
		(width 0.20066)
		(layer "F.Cu")
		(net "M_A_CPU0_SB_DQS_DP<3>")
	)
	(segment
		(start 332.465426 -221.149926)
		(end 332.25232 -220.93682)
		(width 0.088646)
		(layer "F.Cu")
		(net "M_A_CPU0_SB_DQS_DP<3>")
	)
	(segment
		(start 331.355446 -219.981272)
		(end 331.310234 -219.981272)
		(width 0.088646)
		(layer "F.Cu")
		(net "M_A_CPU0_SB_DQS_DP<3>")
	)
	(segment
		(start 307.476144 -200.887076)
		(end 307.928264 -200.434956)
		(width 0.20066)
		(layer "F.Cu")
		(net "M_A_CPU0_SB_DQS_DP<3>")
	)
	(segment
		(start 314.145676 -201.148188)
		(end 314.139072 -201.141584)
		(width 0.1016)
		(layer "F.Cu")
		(net "M_A_CPU0_SB_DQS_DP<3>")
	)
	(segment
		(start 302.356266 -200.465182)
		(end 303.37633 -200.887838)
		(width 0.20066)
		(layer "F.Cu")
		(net "M_A_CPU0_SB_DQS_DP<3>")
	)
	(segment
		(start 331.372464 -210.386422)
		(end 331.33919 -210.306158)
		(width 0.20066)
		(layer "F.Cu")
		(net "M_A_CPU0_SB_DQS_DP<3>")
	)
	(segment
		(start 302.356266 -209.815176)
		(end 303.37633 -210.237832)
		(width 0.20066)
		(layer "F.Cu")
		(net "M_A_CPU0_SB_DQS_DP<2>")
	)
	(segment
		(start 314.795662 -210.214972)
		(end 314.499244 -210.51139)
		(width 0.20066)
		(layer "F.Cu")
		(net "M_A_CPU0_SB_DQS_DP<2>")
	)
	(segment
		(start 332.707488 -230.981504)
		(end 332.237842 -230.981504)
		(width 0.088646)
		(layer "F.Cu")
		(net "M_A_CPU0_SB_DQS_DP<2>")
	)
	(segment
		(start 327.522332 -227.110798)
		(end 327.522332 -224.971356)
		(width 0.1524)
		(layer "F.Cu")
		(net "M_A_CPU0_SB_DQS_DP<2>")
	)
	(segment
		(start 307.476144 -210.23707)
		(end 307.928264 -209.78495)
		(width 0.20066)
		(layer "F.Cu")
		(net "M_A_CPU0_SB_DQS_DP<2>")
	)
	(segment
		(start 325.452994 -216.463118)
		(end 325.401686 -216.463372)
		(width 0.1524)
		(layer "F.Cu")
		(net "M_A_CPU0_SB_DQS_DP<2>")
	)
	(segment
		(start 314.499244 -210.51139)
		(end 314.12688 -210.51139)
		(width 0.20066)
		(layer "F.Cu")
		(net "M_A_CPU0_SB_DQS_DP<2>")
	)
	(segment
		(start 314.107068 -210.51139)
		(end 314.087256 -210.491578)
		(width 0.1016)
		(layer "F.Cu")
		(net "M_A_CPU0_SB_DQS_DP<2>")
	)
	(segment
		(start 327.522332 -224.971356)
		(end 325.917052 -223.366076)
		(width 0.1524)
		(layer "F.Cu")
		(net "M_A_CPU0_SB_DQS_DP<2>")
	)
	(segment
		(start 331.872082 -230.926132)
		(end 331.337666 -230.926132)
		(width 0.1524)
		(layer "F.Cu")
		(net "M_A_CPU0_SB_DQS_DP<2>")
	)
	(segment
		(start 311.47004 -210.500722)
		(end 311.209182 -210.239864)
		(width 0.20066)
		(layer "F.Cu")
		(net "M_A_CPU0_SB_DQS_DP<2>")
	)
	(segment
		(start 304.325528 -210.491832)
		(end 306.634388 -210.491832)
		(width 0.1016)
		(layer "F.Cu")
		(net "M_A_CPU0_SB_DQS_DP<2>")
	)
	(segment
		(start 307.928264 -209.78495)
		(end 308.056788 -209.78495)
		(width 0.20066)
		(layer "F.Cu")
		(net "M_A_CPU0_SB_DQS_DP<2>")
	)
	(segment
		(start 331.92593 -230.894382)
		(end 331.89418 -230.926132)
		(width 0.088646)
		(layer "F.Cu")
		(net "M_A_CPU0_SB_DQS_DP<2>")
	)
	(segment
		(start 332.237842 -230.981504)
		(end 332.15072 -230.894382)
		(width 0.088646)
		(layer "F.Cu")
		(net "M_A_CPU0_SB_DQS_DP<2>")
	)
	(segment
		(start 333.033116 -230.91394)
		(end 332.918816 -230.97998)
		(width 0.088646)
		(layer "F.Cu")
		(net "M_A_CPU0_SB_DQS_DP<2>")
	)
	(segment
		(start 307.203094 -210.23707)
		(end 307.476144 -210.23707)
		(width 0.20066)
		(layer "F.Cu")
		(net "M_A_CPU0_SB_DQS_DP<2>")
	)
	(segment
		(start 304.319178 -210.498182)
		(end 304.319432 -210.497928)
		(width 0.20066)
		(layer "F.Cu")
		(net "M_A_CPU0_SB_DQS_DP<2>")
	)
	(segment
		(start 325.917052 -217.2335)
		(end 325.70039 -216.710514)
		(width 0.1524)
		(layer "F.Cu")
		(net "M_A_CPU0_SB_DQS_DP<2>")
	)
	(segment
		(start 308.056788 -209.78495)
		(end 308.338474 -210.066636)
		(width 0.20066)
		(layer "F.Cu")
		(net "M_A_CPU0_SB_DQS_DP<2>")
	)
	(segment
		(start 331.89418 -230.926132)
		(end 331.872082 -230.926132)
		(width 0.088646)
		(layer "F.Cu")
		(net "M_A_CPU0_SB_DQS_DP<2>")
	)
	(segment
		(start 301.932594 -210.066636)
		(end 302.184054 -209.815176)
		(width 0.20066)
		(layer "F.Cu")
		(net "M_A_CPU0_SB_DQS_DP<2>")
	)
	(segment
		(start 319.153286 -210.214972)
		(end 314.795662 -210.214972)
		(width 0.20066)
		(layer "F.Cu")
		(net "M_A_CPU0_SB_DQS_DP<2>")
	)
	(segment
		(start 333.735934 -230.622602)
		(end 333.033116 -230.91394)
		(width 0.088646)
		(layer "F.Cu")
		(net "M_A_CPU0_SB_DQS_DP<2>")
	)
	(segment
		(start 325.917052 -223.366076)
		(end 325.917052 -217.2335)
		(width 0.1524)
		(layer "F.Cu")
		(net "M_A_CPU0_SB_DQS_DP<2>")
	)
	(segment
		(start 303.932844 -210.498182)
		(end 304.319178 -210.498182)
		(width 0.20066)
		(layer "F.Cu")
		(net "M_A_CPU0_SB_DQS_DP<2>")
	)
	(segment
		(start 314.087256 -210.491578)
		(end 311.995566 -210.491578)
		(width 0.1016)
		(layer "F.Cu")
		(net "M_A_CPU0_SB_DQS_DP<2>")
	)
	(segment
		(start 311.91708 -210.500722)
		(end 311.47004 -210.500722)
		(width 0.20066)
		(layer "F.Cu")
		(net "M_A_CPU0_SB_DQS_DP<2>")
	)
	(segment
		(start 314.12688 -210.51139)
		(end 314.107068 -210.51139)
		(width 0.1016)
		(layer "F.Cu")
		(net "M_A_CPU0_SB_DQS_DP<2>")
	)
	(segment
		(start 304.319432 -210.497928)
		(end 304.325528 -210.491832)
		(width 0.101854)
		(layer "F.Cu")
		(net "M_A_CPU0_SB_DQS_DP<2>")
	)
	(segment
		(start 308.338474 -210.066636)
		(end 308.887114 -210.066636)
		(width 0.20066)
		(layer "F.Cu")
		(net "M_A_CPU0_SB_DQS_DP<2>")
	)
	(segment
		(start 309.7911 -209.821272)
		(end 309.626762 -209.821272)
		(width 0.20066)
		(layer "F.Cu")
		(net "M_A_CPU0_SB_DQS_DP<2>")
	)
	(segment
		(start 306.936902 -210.503262)
		(end 307.203094 -210.23707)
		(width 0.20066)
		(layer "F.Cu")
		(net "M_A_CPU0_SB_DQS_DP<2>")
	)
	(segment
		(start 311.995566 -210.491578)
		(end 311.91708 -210.500722)
		(width 0.1016)
		(layer "F.Cu")
		(net "M_A_CPU0_SB_DQS_DP<2>")
	)
	(segment
		(start 309.381398 -210.066636)
		(end 308.887114 -210.066636)
		(width 0.20066)
		(layer "F.Cu")
		(net "M_A_CPU0_SB_DQS_DP<2>")
	)
	(segment
		(start 325.401686 -216.463372)
		(end 325.374762 -216.436448)
		(width 0.1524)
		(layer "F.Cu")
		(net "M_A_CPU0_SB_DQS_DP<2>")
	)
	(segment
		(start 332.15072 -230.894382)
		(end 331.92593 -230.894382)
		(width 0.088646)
		(layer "F.Cu")
		(net "M_A_CPU0_SB_DQS_DP<2>")
	)
	(segment
		(start 306.644548 -210.501992)
		(end 306.645818 -210.503262)
		(width 0.20066)
		(layer "F.Cu")
		(net "M_A_CPU0_SB_DQS_DP<2>")
	)
	(segment
		(start 303.672494 -210.237832)
		(end 303.932844 -210.498182)
		(width 0.20066)
		(layer "F.Cu")
		(net "M_A_CPU0_SB_DQS_DP<2>")
	)
	(segment
		(start 311.209182 -210.239864)
		(end 310.801766 -210.239864)
		(width 0.20066)
		(layer "F.Cu")
		(net "M_A_CPU0_SB_DQS_DP<2>")
	)
	(segment
		(start 331.337666 -230.926132)
		(end 327.522332 -227.110798)
		(width 0.1524)
		(layer "F.Cu")
		(net "M_A_CPU0_SB_DQS_DP<2>")
	)
	(segment
		(start 310.801766 -210.239864)
		(end 309.7911 -209.821272)
		(width 0.20066)
		(layer "F.Cu")
		(net "M_A_CPU0_SB_DQS_DP<2>")
	)
	(segment
		(start 301.343314 -210.066636)
		(end 301.932594 -210.066636)
		(width 0.20066)
		(layer "F.Cu")
		(net "M_A_CPU0_SB_DQS_DP<2>")
	)
	(segment
		(start 332.918816 -230.97998)
		(end 332.707488 -230.981504)
		(width 0.088646)
		(layer "F.Cu")
		(net "M_A_CPU0_SB_DQS_DP<2>")
	)
	(segment
		(start 325.70039 -216.710514)
		(end 325.452994 -216.463118)
		(width 0.1524)
		(layer "F.Cu")
		(net "M_A_CPU0_SB_DQS_DP<2>")
	)
	(segment
		(start 306.645818 -210.503262)
		(end 306.936902 -210.503262)
		(width 0.20066)
		(layer "F.Cu")
		(net "M_A_CPU0_SB_DQS_DP<2>")
	)
	(segment
		(start 302.184054 -209.815176)
		(end 302.356266 -209.815176)
		(width 0.20066)
		(layer "F.Cu")
		(net "M_A_CPU0_SB_DQS_DP<2>")
	)
	(segment
		(start 325.374762 -216.436448)
		(end 319.153286 -210.214972)
		(width 0.20066)
		(layer "F.Cu")
		(net "M_A_CPU0_SB_DQS_DP<2>")
	)
	(segment
		(start 303.37633 -210.237832)
		(end 303.672494 -210.237832)
		(width 0.20066)
		(layer "F.Cu")
		(net "M_A_CPU0_SB_DQS_DP<2>")
	)
	(segment
		(start 306.634388 -210.491832)
		(end 306.644548 -210.501992)
		(width 0.101854)
		(layer "F.Cu")
		(net "M_A_CPU0_SB_DQS_DP<2>")
	)
	(segment
		(start 309.626762 -209.821272)
		(end 309.381398 -210.066636)
		(width 0.20066)
		(layer "F.Cu")
		(net "M_A_CPU0_SB_DQS_DP<2>")
	)
	(segment
		(start 307.203094 -219.587064)
		(end 307.476144 -219.587064)
		(width 0.20066)
		(layer "F.Cu")
		(net "M_A_CPU0_SB_DQS_DP<1>")
	)
	(segment
		(start 310.864504 -219.590366)
		(end 309.838598 -219.165424)
		(width 0.20066)
		(layer "F.Cu")
		(net "M_A_CPU0_SB_DQS_DP<1>")
	)
	(segment
		(start 324.212966 -230.04526)
		(end 324.174866 -230.04526)
		(width 0.1524)
		(layer "F.Cu")
		(net "M_A_CPU0_SB_DQS_DP<1>")
	)
	(segment
		(start 331.432662 -235.715048)
		(end 331.410564 -235.715048)
		(width 0.088646)
		(layer "F.Cu")
		(net "M_A_CPU0_SB_DQS_DP<1>")
	)
	(segment
		(start 324.350126 -230.006906)
		(end 324.249034 -230.008176)
		(width 0.1524)
		(layer "F.Cu")
		(net "M_A_CPU0_SB_DQS_DP<1>")
	)
	(segment
		(start 303.672494 -219.587826)
		(end 303.932844 -219.848176)
		(width 0.20066)
		(layer "F.Cu")
		(net "M_A_CPU0_SB_DQS_DP<1>")
	)
	(segment
		(start 303.37633 -219.587826)
		(end 303.672494 -219.587826)
		(width 0.20066)
		(layer "F.Cu")
		(net "M_A_CPU0_SB_DQS_DP<1>")
	)
	(segment
		(start 324.956424 -230.137716)
		(end 324.641464 -230.006906)
		(width 0.1524)
		(layer "F.Cu")
		(net "M_A_CPU0_SB_DQS_DP<1>")
	)
	(segment
		(start 331.410564 -235.715048)
		(end 330.53401 -235.715048)
		(width 0.1524)
		(layer "F.Cu")
		(net "M_A_CPU0_SB_DQS_DP<1>")
	)
	(segment
		(start 324.249034 -230.008176)
		(end 324.212966 -230.04526)
		(width 0.1524)
		(layer "F.Cu")
		(net "M_A_CPU0_SB_DQS_DP<1>")
	)
	(segment
		(start 311.87263 -219.841572)
		(end 311.86628 -219.847922)
		(width 0.1016)
		(layer "F.Cu")
		(net "M_A_CPU0_SB_DQS_DP<1>")
	)
	(segment
		(start 330.53401 -235.715048)
		(end 324.956424 -230.137716)
		(width 0.1524)
		(layer "F.Cu")
		(net "M_A_CPU0_SB_DQS_DP<1>")
	)
	(segment
		(start 308.338474 -219.41663)
		(end 308.887114 -219.41663)
		(width 0.20066)
		(layer "F.Cu")
		(net "M_A_CPU0_SB_DQS_DP<1>")
	)
	(segment
		(start 332.057502 -235.867956)
		(end 331.87259 -235.683044)
		(width 0.088646)
		(layer "F.Cu")
		(net "M_A_CPU0_SB_DQS_DP<1>")
	)
	(segment
		(start 333.374238 -235.603034)
		(end 332.97622 -235.833666)
		(width 0.088646)
		(layer "F.Cu")
		(net "M_A_CPU0_SB_DQS_DP<1>")
	)
	(segment
		(start 306.938426 -219.851732)
		(end 307.203094 -219.587064)
		(width 0.20066)
		(layer "F.Cu")
		(net "M_A_CPU0_SB_DQS_DP<1>")
	)
	(segment
		(start 314.484258 -219.849192)
		(end 314.188094 -219.849192)
		(width 0.20066)
		(layer "F.Cu")
		(net "M_A_CPU0_SB_DQS_DP<1>")
	)
	(segment
		(start 332.848712 -235.867956)
		(end 332.057502 -235.867956)
		(width 0.088646)
		(layer "F.Cu")
		(net "M_A_CPU0_SB_DQS_DP<1>")
	)
	(segment
		(start 318.057022 -222.53575)
		(end 315.101986 -219.580714)
		(width 0.20066)
		(layer "F.Cu")
		(net "M_A_CPU0_SB_DQS_DP<1>")
	)
	(segment
		(start 331.87259 -235.683044)
		(end 331.464666 -235.683044)
		(width 0.088646)
		(layer "F.Cu")
		(net "M_A_CPU0_SB_DQS_DP<1>")
	)
	(segment
		(start 318.057022 -227.626418)
		(end 318.057022 -222.53575)
		(width 0.20066)
		(layer "F.Cu")
		(net "M_A_CPU0_SB_DQS_DP<1>")
	)
	(segment
		(start 301.932594 -219.41663)
		(end 302.184054 -219.16517)
		(width 0.20066)
		(layer "F.Cu")
		(net "M_A_CPU0_SB_DQS_DP<1>")
	)
	(segment
		(start 320.475864 -230.04526)
		(end 318.057022 -227.626418)
		(width 0.20066)
		(layer "F.Cu")
		(net "M_A_CPU0_SB_DQS_DP<1>")
	)
	(segment
		(start 314.188094 -219.849192)
		(end 314.180474 -219.841572)
		(width 0.1016)
		(layer "F.Cu")
		(net "M_A_CPU0_SB_DQS_DP<1>")
	)
	(segment
		(start 307.476144 -219.587064)
		(end 307.928264 -219.134944)
		(width 0.20066)
		(layer "F.Cu")
		(net "M_A_CPU0_SB_DQS_DP<1>")
	)
	(segment
		(start 311.181242 -219.590366)
		(end 310.864504 -219.590366)
		(width 0.20066)
		(layer "F.Cu")
		(net "M_A_CPU0_SB_DQS_DP<1>")
	)
	(segment
		(start 304.325528 -219.841826)
		(end 306.634388 -219.841826)
		(width 0.1016)
		(layer "F.Cu")
		(net "M_A_CPU0_SB_DQS_DP<1>")
	)
	(segment
		(start 304.319178 -219.848176)
		(end 304.325528 -219.841826)
		(width 0.1016)
		(layer "F.Cu")
		(net "M_A_CPU0_SB_DQS_DP<1>")
	)
	(segment
		(start 302.184054 -219.16517)
		(end 302.356266 -219.16517)
		(width 0.20066)
		(layer "F.Cu")
		(net "M_A_CPU0_SB_DQS_DP<1>")
	)
	(segment
		(start 306.634388 -219.841826)
		(end 306.644294 -219.851732)
		(width 0.1016)
		(layer "F.Cu")
		(net "M_A_CPU0_SB_DQS_DP<1>")
	)
	(segment
		(start 324.174866 -230.04526)
		(end 320.475864 -230.04526)
		(width 0.20066)
		(layer "F.Cu")
		(net "M_A_CPU0_SB_DQS_DP<1>")
	)
	(segment
		(start 307.928264 -219.134944)
		(end 308.056788 -219.134944)
		(width 0.20066)
		(layer "F.Cu")
		(net "M_A_CPU0_SB_DQS_DP<1>")
	)
	(segment
		(start 309.632604 -219.165424)
		(end 309.381398 -219.41663)
		(width 0.20066)
		(layer "F.Cu")
		(net "M_A_CPU0_SB_DQS_DP<1>")
	)
	(segment
		(start 308.056788 -219.134944)
		(end 308.338474 -219.41663)
		(width 0.20066)
		(layer "F.Cu")
		(net "M_A_CPU0_SB_DQS_DP<1>")
	)
	(segment
		(start 302.356266 -219.16517)
		(end 303.37633 -219.587826)
		(width 0.20066)
		(layer "F.Cu")
		(net "M_A_CPU0_SB_DQS_DP<1>")
	)
	(segment
		(start 306.644294 -219.851732)
		(end 306.938426 -219.851732)
		(width 0.20066)
		(layer "F.Cu")
		(net "M_A_CPU0_SB_DQS_DP<1>")
	)
	(segment
		(start 309.381398 -219.41663)
		(end 308.887114 -219.41663)
		(width 0.20066)
		(layer "F.Cu")
		(net "M_A_CPU0_SB_DQS_DP<1>")
	)
	(segment
		(start 333.735934 -235.506006)
		(end 333.374238 -235.603034)
		(width 0.088646)
		(layer "F.Cu")
		(net "M_A_CPU0_SB_DQS_DP<1>")
	)
	(segment
		(start 331.464666 -235.683044)
		(end 331.432662 -235.715048)
		(width 0.088646)
		(layer "F.Cu")
		(net "M_A_CPU0_SB_DQS_DP<1>")
	)
	(segment
		(start 324.641464 -230.006906)
		(end 324.350126 -230.006906)
		(width 0.1524)
		(layer "F.Cu")
		(net "M_A_CPU0_SB_DQS_DP<1>")
	)
	(segment
		(start 303.932844 -219.848176)
		(end 304.319178 -219.848176)
		(width 0.20066)
		(layer "F.Cu")
		(net "M_A_CPU0_SB_DQS_DP<1>")
	)
	(segment
		(start 309.838598 -219.165424)
		(end 309.632604 -219.165424)
		(width 0.20066)
		(layer "F.Cu")
		(net "M_A_CPU0_SB_DQS_DP<1>")
	)
	(segment
		(start 315.101986 -219.580714)
		(end 314.752736 -219.580714)
		(width 0.20066)
		(layer "F.Cu")
		(net "M_A_CPU0_SB_DQS_DP<1>")
	)
	(segment
		(start 311.438798 -219.847922)
		(end 311.181242 -219.590366)
		(width 0.20066)
		(layer "F.Cu")
		(net "M_A_CPU0_SB_DQS_DP<1>")
	)
	(segment
		(start 314.752736 -219.580714)
		(end 314.484258 -219.849192)
		(width 0.20066)
		(layer "F.Cu")
		(net "M_A_CPU0_SB_DQS_DP<1>")
	)
	(segment
		(start 301.343314 -219.41663)
		(end 301.932594 -219.41663)
		(width 0.20066)
		(layer "F.Cu")
		(net "M_A_CPU0_SB_DQS_DP<1>")
	)
	(segment
		(start 311.86628 -219.847922)
		(end 311.438798 -219.847922)
		(width 0.20066)
		(layer "F.Cu")
		(net "M_A_CPU0_SB_DQS_DP<1>")
	)
	(segment
		(start 314.180474 -219.841572)
		(end 311.87263 -219.841572)
		(width 0.1016)
		(layer "F.Cu")
		(net "M_A_CPU0_SB_DQS_DP<1>")
	)
	(arc
		(start 332.97622 -235.833666)
		(mid 332.914739 -235.859281)
		(end 332.848712 -235.867956)
		(width 0.088646)
		(layer "F.Cu")
		(net "M_A_CPU0_SB_DQS_DP<1>")
	)
	(segment
		(start 307.377084 -228.937058)
		(end 307.04663 -228.937058)
		(width 0.20066)
		(layer "F.Cu")
		(net "M_A_CPU0_SB_DQS_DP<0>")
	)
	(segment
		(start 304.333148 -229.19182)
		(end 304.319178 -229.20579)
		(width 0.101854)
		(layer "F.Cu")
		(net "M_A_CPU0_SB_DQS_DP<0>")
	)
	(segment
		(start 308.887114 -228.766624)
		(end 308.338474 -228.766624)
		(width 0.20066)
		(layer "F.Cu")
		(net "M_A_CPU0_SB_DQS_DP<0>")
	)
	(segment
		(start 303.846484 -228.94671)
		(end 303.515268 -228.94671)
		(width 0.20066)
		(layer "F.Cu")
		(net "M_A_CPU0_SB_DQS_DP<0>")
	)
	(segment
		(start 337.02498 -237.947454)
		(end 337.02498 -237.411768)
		(width 0.20066)
		(layer "F.Cu")
		(net "M_A_CPU0_SB_DQS_DP<0>")
	)
	(segment
		(start 304.565558 -229.19182)
		(end 304.333148 -229.19182)
		(width 0.101854)
		(layer "F.Cu")
		(net "M_A_CPU0_SB_DQS_DP<0>")
	)
	(segment
		(start 302.473614 -228.515164)
		(end 302.184054 -228.515164)
		(width 0.20066)
		(layer "F.Cu")
		(net "M_A_CPU0_SB_DQS_DP<0>")
	)
	(segment
		(start 306.644294 -229.19182)
		(end 306.320952 -229.19182)
		(width 0.101854)
		(layer "F.Cu")
		(net "M_A_CPU0_SB_DQS_DP<0>")
	)
	(segment
		(start 306.791868 -229.19182)
		(end 306.644294 -229.19182)
		(width 0.20066)
		(layer "F.Cu")
		(net "M_A_CPU0_SB_DQS_DP<0>")
	)
	(segment
		(start 309.992014 -228.766624)
		(end 308.887114 -228.766624)
		(width 0.20066)
		(layer "F.Cu")
		(net "M_A_CPU0_SB_DQS_DP<0>")
	)
	(segment
		(start 304.319178 -229.20579)
		(end 304.105564 -229.20579)
		(width 0.20066)
		(layer "F.Cu")
		(net "M_A_CPU0_SB_DQS_DP<0>")
	)
	(segment
		(start 308.056788 -228.484938)
		(end 307.829204 -228.484938)
		(width 0.20066)
		(layer "F.Cu")
		(net "M_A_CPU0_SB_DQS_DP<0>")
	)
	(segment
		(start 337.02498 -237.411768)
		(end 337.025234 -237.411514)
		(width 0.20066)
		(layer "F.Cu")
		(net "M_A_CPU0_SB_DQS_DP<0>")
	)
	(segment
		(start 302.184054 -228.515164)
		(end 301.932594 -228.766624)
		(width 0.20066)
		(layer "F.Cu")
		(net "M_A_CPU0_SB_DQS_DP<0>")
	)
	(segment
		(start 307.04663 -228.937058)
		(end 306.791868 -229.19182)
		(width 0.20066)
		(layer "F.Cu")
		(net "M_A_CPU0_SB_DQS_DP<0>")
	)
	(segment
		(start 306.320952 -229.19182)
		(end 304.565558 -229.19182)
		(width 0.1016)
		(layer "F.Cu")
		(net "M_A_CPU0_SB_DQS_DP<0>")
	)
	(segment
		(start 307.829204 -228.484938)
		(end 307.377084 -228.937058)
		(width 0.20066)
		(layer "F.Cu")
		(net "M_A_CPU0_SB_DQS_DP<0>")
	)
	(segment
		(start 308.338474 -228.766624)
		(end 308.056788 -228.484938)
		(width 0.20066)
		(layer "F.Cu")
		(net "M_A_CPU0_SB_DQS_DP<0>")
	)
	(segment
		(start 304.105564 -229.20579)
		(end 303.846484 -228.94671)
		(width 0.20066)
		(layer "F.Cu")
		(net "M_A_CPU0_SB_DQS_DP<0>")
	)
	(segment
		(start 301.932594 -228.766624)
		(end 301.343314 -228.766624)
		(width 0.20066)
		(layer "F.Cu")
		(net "M_A_CPU0_SB_DQS_DP<0>")
	)
	(segment
		(start 303.515268 -228.94671)
		(end 302.473614 -228.515164)
		(width 0.20066)
		(layer "F.Cu")
		(net "M_A_CPU0_SB_DQS_DP<0>")
	)
	(segment
		(start 334.863186 -237.900972)
		(end 334.862932 -237.901226)
		(width 0.088646)
		(layer "In2.Cu")
		(net "M_A_CPU0_SB_DQS_DP<0>")
	)
	(segment
		(start 312.138568 -228.620066)
		(end 311.938416 -228.419914)
		(width 0.16002)
		(layer "In2.Cu")
		(net "M_A_CPU0_SB_DQS_DP<0>")
	)
	(segment
		(start 312.138568 -228.635814)
		(end 312.138568 -228.620066)
		(width 0.16002)
		(layer "In2.Cu")
		(net "M_A_CPU0_SB_DQS_DP<0>")
	)
	(segment
		(start 313.989466 -229.19182)
		(end 313.901074 -229.19182)
		(width 0.18288)
		(layer "In2.Cu")
		(net "M_A_CPU0_SB_DQS_DP<0>")
	)
	(segment
		(start 311.922668 -228.419914)
		(end 311.894474 -228.39172)
		(width 0.16002)
		(layer "In2.Cu")
		(net "M_A_CPU0_SB_DQS_DP<0>")
	)
	(segment
		(start 331.794104 -237.83417)
		(end 330.759054 -237.83417)
		(width 0.088646)
		(layer "In2.Cu")
		(net "M_A_CPU0_SB_DQS_DP<0>")
	)
	(segment
		(start 337.025234 -237.411514)
		(end 336.647282 -237.411768)
		(width 0.088646)
		(layer "In2.Cu")
		(net "M_A_CPU0_SB_DQS_DP<0>")
	)
	(segment
		(start 336.054954 -237.785656)
		(end 335.857596 -237.785656)
		(width 0.088646)
		(layer "In2.Cu")
		(net "M_A_CPU0_SB_DQS_DP<0>")
	)
	(segment
		(start 336.055462 -237.785148)
		(end 336.054954 -237.785656)
		(width 0.088646)
		(layer "In2.Cu")
		(net "M_A_CPU0_SB_DQS_DP<0>")
	)
	(segment
		(start 312.166762 -228.664008)
		(end 312.138568 -228.635814)
		(width 0.16002)
		(layer "In2.Cu")
		(net "M_A_CPU0_SB_DQS_DP<0>")
	)
	(segment
		(start 332.998064 -237.909862)
		(end 332.983332 -237.901226)
		(width 0.088646)
		(layer "In2.Cu")
		(net "M_A_CPU0_SB_DQS_DP<0>")
	)
	(segment
		(start 336.647282 -237.411768)
		(end 336.366104 -237.692946)
		(width 0.088646)
		(layer "In2.Cu")
		(net "M_A_CPU0_SB_DQS_DP<0>")
	)
	(segment
		(start 312.399172 -228.896418)
		(end 312.166762 -228.664008)
		(width 0.18288)
		(layer "In2.Cu")
		(net "M_A_CPU0_SB_DQS_DP<0>")
	)
	(segment
		(start 330.699364 -237.89386)
		(end 327.428098 -237.89386)
		(width 0.18288)
		(layer "In2.Cu")
		(net "M_A_CPU0_SB_DQS_DP<0>")
	)
	(segment
		(start 314.164726 -229.19182)
		(end 313.989466 -229.19182)
		(width 0.16002)
		(layer "In2.Cu")
		(net "M_A_CPU0_SB_DQS_DP<0>")
	)
	(segment
		(start 311.894474 -228.39172)
		(end 311.743852 -228.241098)
		(width 0.18288)
		(layer "In2.Cu")
		(net "M_A_CPU0_SB_DQS_DP<0>")
	)
	(segment
		(start 313.901074 -229.19182)
		(end 313.605672 -228.896418)
		(width 0.18288)
		(layer "In2.Cu")
		(net "M_A_CPU0_SB_DQS_DP<0>")
	)
	(segment
		(start 314.555632 -228.915976)
		(end 314.279788 -229.19182)
		(width 0.18288)
		(layer "In2.Cu")
		(net "M_A_CPU0_SB_DQS_DP<0>")
	)
	(segment
		(start 318.450214 -228.915976)
		(end 314.555632 -228.915976)
		(width 0.18288)
		(layer "In2.Cu")
		(net "M_A_CPU0_SB_DQS_DP<0>")
	)
	(segment
		(start 336.065876 -237.785656)
		(end 336.055462 -237.785148)
		(width 0.088646)
		(layer "In2.Cu")
		(net "M_A_CPU0_SB_DQS_DP<0>")
	)
	(segment
		(start 311.743852 -228.241098)
		(end 311.290716 -228.241098)
		(width 0.18288)
		(layer "In2.Cu")
		(net "M_A_CPU0_SB_DQS_DP<0>")
	)
	(segment
		(start 310.673496 -228.496622)
		(end 310.262016 -228.496622)
		(width 0.18288)
		(layer "In2.Cu")
		(net "M_A_CPU0_SB_DQS_DP<0>")
	)
	(segment
		(start 332.058264 -237.909862)
		(end 332.043532 -237.901226)
		(width 0.088646)
		(layer "In2.Cu")
		(net "M_A_CPU0_SB_DQS_DP<0>")
	)
	(segment
		(start 330.759054 -237.83417)
		(end 330.699364 -237.89386)
		(width 0.088646)
		(layer "In2.Cu")
		(net "M_A_CPU0_SB_DQS_DP<0>")
	)
	(segment
		(start 311.290716 -228.241098)
		(end 310.673496 -228.496622)
		(width 0.18288)
		(layer "In2.Cu")
		(net "M_A_CPU0_SB_DQS_DP<0>")
	)
	(segment
		(start 310.262016 -228.496622)
		(end 309.992014 -228.766624)
		(width 0.18288)
		(layer "In2.Cu")
		(net "M_A_CPU0_SB_DQS_DP<0>")
	)
	(segment
		(start 311.938416 -228.419914)
		(end 311.922668 -228.419914)
		(width 0.16002)
		(layer "In2.Cu")
		(net "M_A_CPU0_SB_DQS_DP<0>")
	)
	(segment
		(start 314.279788 -229.19182)
		(end 314.164726 -229.19182)
		(width 0.18288)
		(layer "In2.Cu")
		(net "M_A_CPU0_SB_DQS_DP<0>")
	)
	(segment
		(start 313.605672 -228.896418)
		(end 312.399172 -228.896418)
		(width 0.18288)
		(layer "In2.Cu")
		(net "M_A_CPU0_SB_DQS_DP<0>")
	)
	(segment
		(start 327.428098 -237.89386)
		(end 318.450214 -228.915976)
		(width 0.18288)
		(layer "In2.Cu")
		(net "M_A_CPU0_SB_DQS_DP<0>")
	)
	(arc
		(start 335.857596 -237.785656)
		(mid 335.634851 -237.814942)
		(end 335.42732 -237.900972)
		(width 0.088646)
		(layer "In2.Cu")
		(net "M_A_CPU0_SB_DQS_DP<0>")
	)
	(arc
		(start 332.608936 -237.901226)
		(mid 332.334737 -237.977061)
		(end 332.058264 -237.909862)
		(width 0.088646)
		(layer "In2.Cu")
		(net "M_A_CPU0_SB_DQS_DP<0>")
	)
	(arc
		(start 333.548736 -237.901226)
		(mid 333.274537 -237.977061)
		(end 332.998064 -237.909862)
		(width 0.088646)
		(layer "In2.Cu")
		(net "M_A_CPU0_SB_DQS_DP<0>")
	)
	(arc
		(start 332.043532 -237.901226)
		(mid 331.923252 -237.851192)
		(end 331.794104 -237.83417)
		(width 0.088646)
		(layer "In2.Cu")
		(net "M_A_CPU0_SB_DQS_DP<0>")
	)
	(arc
		(start 335.42732 -237.900972)
		(mid 335.14527 -237.976401)
		(end 334.863186 -237.900972)
		(width 0.088646)
		(layer "In2.Cu")
		(net "M_A_CPU0_SB_DQS_DP<0>")
	)
	(arc
		(start 332.983332 -237.901226)
		(mid 332.796134 -237.851083)
		(end 332.608936 -237.901226)
		(width 0.088646)
		(layer "In2.Cu")
		(net "M_A_CPU0_SB_DQS_DP<0>")
	)
	(arc
		(start 336.366104 -237.692946)
		(mid 336.318251 -237.712387)
		(end 336.272378 -237.736126)
		(width 0.088646)
		(layer "In2.Cu")
		(net "M_A_CPU0_SB_DQS_DP<0>")
	)
	(arc
		(start 333.923132 -237.901226)
		(mid 333.735934 -237.851083)
		(end 333.548736 -237.901226)
		(width 0.088646)
		(layer "In2.Cu")
		(net "M_A_CPU0_SB_DQS_DP<0>")
	)
	(arc
		(start 334.862932 -237.901226)
		(mid 334.675734 -237.851083)
		(end 334.488536 -237.901226)
		(width 0.088646)
		(layer "In2.Cu")
		(net "M_A_CPU0_SB_DQS_DP<0>")
	)
	(arc
		(start 336.272378 -237.736126)
		(mid 336.172711 -237.775827)
		(end 336.065876 -237.785656)
		(width 0.088646)
		(layer "In2.Cu")
		(net "M_A_CPU0_SB_DQS_DP<0>")
	)
	(arc
		(start 334.488536 -237.901226)
		(mid 334.205834 -237.977002)
		(end 333.923132 -237.901226)
		(width 0.088646)
		(layer "In2.Cu")
		(net "M_A_CPU0_SB_DQS_DP<0>")
	)
	(segment
		(start 314.545726 -237.691676)
		(end 314.457588 -237.691676)
		(width 0.20066)
		(layer "F.Cu")
		(net "M_A_CPU0_SB_DQS_DN<9>")
	)
	(segment
		(start 303.938178 -237.691676)
		(end 303.972214 -237.691676)
		(width 0.20066)
		(layer "F.Cu")
		(net "M_A_CPU0_SB_DQS_DN<9>")
	)
	(segment
		(start 331.861668 -240.292636)
		(end 331.559408 -240.29289)
		(width 0.088646)
		(layer "F.Cu")
		(net "M_A_CPU0_SB_DQS_DN<9>")
	)
	(segment
		(start 309.379874 -237.266734)
		(end 308.887114 -237.266734)
		(width 0.20066)
		(layer "F.Cu")
		(net "M_A_CPU0_SB_DQS_DN<9>")
	)
	(segment
		(start 301.343314 -237.266734)
		(end 301.891954 -237.266734)
		(width 0.20066)
		(layer "F.Cu")
		(net "M_A_CPU0_SB_DQS_DN<9>")
	)
	(segment
		(start 332.236826 -240.426748)
		(end 332.139036 -240.40719)
		(width 0.088646)
		(layer "F.Cu")
		(net "M_A_CPU0_SB_DQS_DN<9>")
	)
	(segment
		(start 316.905386 -238.536734)
		(end 316.780926 -238.661194)
		(width 0.20066)
		(layer "F.Cu")
		(net "M_A_CPU0_SB_DQS_DN<9>")
	)
	(segment
		(start 311.522364 -237.691676)
		(end 311.469786 -237.691676)
		(width 0.20066)
		(layer "F.Cu")
		(net "M_A_CPU0_SB_DQS_DN<9>")
	)
	(segment
		(start 309.380128 -237.26648)
		(end 309.379874 -237.266734)
		(width 0.20066)
		(layer "F.Cu")
		(net "M_A_CPU0_SB_DQS_DN<9>")
	)
	(segment
		(start 327.468484 -240.11255)
		(end 326.866504 -240.11255)
		(width 0.20066)
		(layer "F.Cu")
		(net "M_A_CPU0_SB_DQS_DN<9>")
	)
	(segment
		(start 307.792374 -237.507272)
		(end 308.057296 -237.507272)
		(width 0.20066)
		(layer "F.Cu")
		(net "M_A_CPU0_SB_DQS_DN<9>")
	)
	(segment
		(start 327.592944 -239.98809)
		(end 327.468484 -240.11255)
		(width 0.20066)
		(layer "F.Cu")
		(net "M_A_CPU0_SB_DQS_DN<9>")
	)
	(segment
		(start 331.28966 -240.18113)
		(end 330.931012 -240.18113)
		(width 0.088646)
		(layer "F.Cu")
		(net "M_A_CPU0_SB_DQS_DN<9>")
	)
	(segment
		(start 318.358266 -238.536734)
		(end 318.233806 -238.661194)
		(width 0.20066)
		(layer "F.Cu")
		(net "M_A_CPU0_SB_DQS_DN<9>")
	)
	(segment
		(start 308.297834 -237.266734)
		(end 308.887114 -237.266734)
		(width 0.20066)
		(layer "F.Cu")
		(net "M_A_CPU0_SB_DQS_DN<9>")
	)
	(segment
		(start 308.057296 -237.507272)
		(end 308.297834 -237.266734)
		(width 0.20066)
		(layer "F.Cu")
		(net "M_A_CPU0_SB_DQS_DN<9>")
	)
	(segment
		(start 326.866504 -240.11255)
		(end 326.742044 -239.98809)
		(width 0.20066)
		(layer "F.Cu")
		(net "M_A_CPU0_SB_DQS_DN<9>")
	)
	(segment
		(start 330.877164 -240.14938)
		(end 328.996294 -240.14938)
		(width 0.1524)
		(layer "F.Cu")
		(net "M_A_CPU0_SB_DQS_DN<9>")
	)
	(segment
		(start 301.891954 -237.266734)
		(end 302.162718 -237.537498)
		(width 0.20066)
		(layer "F.Cu")
		(net "M_A_CPU0_SB_DQS_DN<9>")
	)
	(segment
		(start 328.194924 -239.98809)
		(end 327.592944 -239.98809)
		(width 0.20066)
		(layer "F.Cu")
		(net "M_A_CPU0_SB_DQS_DN<9>")
	)
	(segment
		(start 321.7545 -239.433862)
		(end 321.59194 -239.501172)
		(width 0.20066)
		(layer "F.Cu")
		(net "M_A_CPU0_SB_DQS_DN<9>")
	)
	(segment
		(start 314.974224 -238.2139)
		(end 314.73775 -237.977426)
		(width 0.20066)
		(layer "F.Cu")
		(net "M_A_CPU0_SB_DQS_DN<9>")
	)
	(segment
		(start 309.6514 -237.537752)
		(end 309.380128 -237.26648)
		(width 0.20066)
		(layer "F.Cu")
		(net "M_A_CPU0_SB_DQS_DN<9>")
	)
	(segment
		(start 317.631826 -238.661194)
		(end 317.507366 -238.536734)
		(width 0.20066)
		(layer "F.Cu")
		(net "M_A_CPU0_SB_DQS_DN<9>")
	)
	(segment
		(start 328.959464 -240.11255)
		(end 328.921364 -240.11255)
		(width 0.1524)
		(layer "F.Cu")
		(net "M_A_CPU0_SB_DQS_DN<9>")
	)
	(segment
		(start 317.507366 -238.536734)
		(end 316.905386 -238.536734)
		(width 0.20066)
		(layer "F.Cu")
		(net "M_A_CPU0_SB_DQS_DN<9>")
	)
	(segment
		(start 322.377816 -239.82553)
		(end 322.311014 -239.664494)
		(width 0.20066)
		(layer "F.Cu")
		(net "M_A_CPU0_SB_DQS_DN<9>")
	)
	(segment
		(start 310.288178 -237.537752)
		(end 309.6514 -237.537752)
		(width 0.20066)
		(layer "F.Cu")
		(net "M_A_CPU0_SB_DQS_DN<9>")
	)
	(segment
		(start 311.198768 -237.962694)
		(end 310.71312 -237.962694)
		(width 0.20066)
		(layer "F.Cu")
		(net "M_A_CPU0_SB_DQS_DN<9>")
	)
	(segment
		(start 323.070982 -240.11255)
		(end 322.377816 -239.82553)
		(width 0.20066)
		(layer "F.Cu")
		(net "M_A_CPU0_SB_DQS_DN<9>")
	)
	(segment
		(start 302.70196 -237.537498)
		(end 303.124616 -237.960154)
		(width 0.20066)
		(layer "F.Cu")
		(net "M_A_CPU0_SB_DQS_DN<9>")
	)
	(segment
		(start 332.139036 -240.40719)
		(end 331.861668 -240.292636)
		(width 0.088646)
		(layer "F.Cu")
		(net "M_A_CPU0_SB_DQS_DN<9>")
	)
	(segment
		(start 303.972214 -237.691676)
		(end 306.907946 -237.691676)
		(width 0.1016)
		(layer "F.Cu")
		(net "M_A_CPU0_SB_DQS_DN<9>")
	)
	(segment
		(start 318.960246 -238.536734)
		(end 318.358266 -238.536734)
		(width 0.20066)
		(layer "F.Cu")
		(net "M_A_CPU0_SB_DQS_DN<9>")
	)
	(segment
		(start 321.035934 -239.271048)
		(end 320.968624 -239.108488)
		(width 0.20066)
		(layer "F.Cu")
		(net "M_A_CPU0_SB_DQS_DN<9>")
	)
	(segment
		(start 324.687184 -239.98809)
		(end 324.562724 -240.11255)
		(width 0.20066)
		(layer "F.Cu")
		(net "M_A_CPU0_SB_DQS_DN<9>")
	)
	(segment
		(start 303.6697 -237.960154)
		(end 303.938178 -237.691676)
		(width 0.20066)
		(layer "F.Cu")
		(net "M_A_CPU0_SB_DQS_DN<9>")
	)
	(segment
		(start 316.178946 -238.661194)
		(end 315.731652 -238.2139)
		(width 0.20066)
		(layer "F.Cu")
		(net "M_A_CPU0_SB_DQS_DN<9>")
	)
	(segment
		(start 321.59194 -239.501172)
		(end 321.035934 -239.271048)
		(width 0.20066)
		(layer "F.Cu")
		(net "M_A_CPU0_SB_DQS_DN<9>")
	)
	(segment
		(start 307.165502 -237.908846)
		(end 307.350922 -237.908846)
		(width 0.20066)
		(layer "F.Cu")
		(net "M_A_CPU0_SB_DQS_DN<9>")
	)
	(segment
		(start 330.931012 -240.18113)
		(end 330.899262 -240.14938)
		(width 0.088646)
		(layer "F.Cu")
		(net "M_A_CPU0_SB_DQS_DN<9>")
	)
	(segment
		(start 324.562724 -240.11255)
		(end 323.070982 -240.11255)
		(width 0.20066)
		(layer "F.Cu")
		(net "M_A_CPU0_SB_DQS_DN<9>")
	)
	(segment
		(start 326.742044 -239.98809)
		(end 326.140064 -239.98809)
		(width 0.20066)
		(layer "F.Cu")
		(net "M_A_CPU0_SB_DQS_DN<9>")
	)
	(segment
		(start 311.469786 -237.691676)
		(end 311.198768 -237.962694)
		(width 0.20066)
		(layer "F.Cu")
		(net "M_A_CPU0_SB_DQS_DN<9>")
	)
	(segment
		(start 306.907946 -237.691676)
		(end 306.948332 -237.691676)
		(width 0.20066)
		(layer "F.Cu")
		(net "M_A_CPU0_SB_DQS_DN<9>")
	)
	(segment
		(start 314.73775 -237.8837)
		(end 314.545726 -237.691676)
		(width 0.20066)
		(layer "F.Cu")
		(net "M_A_CPU0_SB_DQS_DN<9>")
	)
	(segment
		(start 307.419248 -237.880398)
		(end 307.792374 -237.507272)
		(width 0.20066)
		(layer "F.Cu")
		(net "M_A_CPU0_SB_DQS_DN<9>")
	)
	(segment
		(start 325.289164 -239.98809)
		(end 324.687184 -239.98809)
		(width 0.20066)
		(layer "F.Cu")
		(net "M_A_CPU0_SB_DQS_DN<9>")
	)
	(segment
		(start 310.71312 -237.962694)
		(end 310.288178 -237.537752)
		(width 0.20066)
		(layer "F.Cu")
		(net "M_A_CPU0_SB_DQS_DN<9>")
	)
	(segment
		(start 326.015604 -240.11255)
		(end 325.413624 -240.11255)
		(width 0.20066)
		(layer "F.Cu")
		(net "M_A_CPU0_SB_DQS_DN<9>")
	)
	(segment
		(start 319.084706 -238.661194)
		(end 318.960246 -238.536734)
		(width 0.20066)
		(layer "F.Cu")
		(net "M_A_CPU0_SB_DQS_DN<9>")
	)
	(segment
		(start 326.140064 -239.98809)
		(end 326.015604 -240.11255)
		(width 0.20066)
		(layer "F.Cu")
		(net "M_A_CPU0_SB_DQS_DN<9>")
	)
	(segment
		(start 320.968624 -239.108488)
		(end 320.41211 -238.877856)
		(width 0.20066)
		(layer "F.Cu")
		(net "M_A_CPU0_SB_DQS_DN<9>")
	)
	(segment
		(start 330.899262 -240.14938)
		(end 330.877164 -240.14938)
		(width 0.088646)
		(layer "F.Cu")
		(net "M_A_CPU0_SB_DQS_DN<9>")
	)
	(segment
		(start 328.319384 -240.11255)
		(end 328.194924 -239.98809)
		(width 0.20066)
		(layer "F.Cu")
		(net "M_A_CPU0_SB_DQS_DN<9>")
	)
	(segment
		(start 319.563242 -238.661194)
		(end 319.084706 -238.661194)
		(width 0.20066)
		(layer "F.Cu")
		(net "M_A_CPU0_SB_DQS_DN<9>")
	)
	(segment
		(start 303.124616 -237.960154)
		(end 303.6697 -237.960154)
		(width 0.20066)
		(layer "F.Cu")
		(net "M_A_CPU0_SB_DQS_DN<9>")
	)
	(segment
		(start 307.350922 -237.908846)
		(end 307.419248 -237.880398)
		(width 0.20066)
		(layer "F.Cu")
		(net "M_A_CPU0_SB_DQS_DN<9>")
	)
	(segment
		(start 328.996294 -240.14938)
		(end 328.959464 -240.11255)
		(width 0.1524)
		(layer "F.Cu")
		(net "M_A_CPU0_SB_DQS_DN<9>")
	)
	(segment
		(start 302.162718 -237.537498)
		(end 302.70196 -237.537498)
		(width 0.20066)
		(layer "F.Cu")
		(net "M_A_CPU0_SB_DQS_DN<9>")
	)
	(segment
		(start 314.73775 -237.977426)
		(end 314.73775 -237.8837)
		(width 0.20066)
		(layer "F.Cu")
		(net "M_A_CPU0_SB_DQS_DN<9>")
	)
	(segment
		(start 314.457588 -237.691676)
		(end 311.522364 -237.691676)
		(width 0.1016)
		(layer "F.Cu")
		(net "M_A_CPU0_SB_DQS_DN<9>")
	)
	(segment
		(start 320.24955 -238.94542)
		(end 319.563242 -238.661194)
		(width 0.20066)
		(layer "F.Cu")
		(net "M_A_CPU0_SB_DQS_DN<9>")
	)
	(segment
		(start 322.311014 -239.664494)
		(end 321.7545 -239.433862)
		(width 0.20066)
		(layer "F.Cu")
		(net "M_A_CPU0_SB_DQS_DN<9>")
	)
	(segment
		(start 318.233806 -238.661194)
		(end 317.631826 -238.661194)
		(width 0.20066)
		(layer "F.Cu")
		(net "M_A_CPU0_SB_DQS_DN<9>")
	)
	(segment
		(start 316.780926 -238.661194)
		(end 316.178946 -238.661194)
		(width 0.20066)
		(layer "F.Cu")
		(net "M_A_CPU0_SB_DQS_DN<9>")
	)
	(segment
		(start 328.921364 -240.11255)
		(end 328.319384 -240.11255)
		(width 0.20066)
		(layer "F.Cu")
		(net "M_A_CPU0_SB_DQS_DN<9>")
	)
	(segment
		(start 331.559408 -240.29289)
		(end 331.28966 -240.18113)
		(width 0.088646)
		(layer "F.Cu")
		(net "M_A_CPU0_SB_DQS_DN<9>")
	)
	(segment
		(start 325.413624 -240.11255)
		(end 325.289164 -239.98809)
		(width 0.20066)
		(layer "F.Cu")
		(net "M_A_CPU0_SB_DQS_DN<9>")
	)
	(segment
		(start 306.948332 -237.691676)
		(end 307.165502 -237.908846)
		(width 0.20066)
		(layer "F.Cu")
		(net "M_A_CPU0_SB_DQS_DN<9>")
	)
	(segment
		(start 315.731652 -238.2139)
		(end 314.974224 -238.2139)
		(width 0.20066)
		(layer "F.Cu")
		(net "M_A_CPU0_SB_DQS_DN<9>")
	)
	(segment
		(start 332.705456 -240.426748)
		(end 332.236826 -240.426748)
		(width 0.088646)
		(layer "F.Cu")
		(net "M_A_CPU0_SB_DQS_DN<9>")
	)
	(segment
		(start 320.41211 -238.877856)
		(end 320.24955 -238.94542)
		(width 0.20066)
		(layer "F.Cu")
		(net "M_A_CPU0_SB_DQS_DN<9>")
	)
	(arc
		(start 332.796134 -240.389156)
		(mid 332.754531 -240.416955)
		(end 332.705456 -240.426748)
		(width 0.088646)
		(layer "F.Cu")
		(net "M_A_CPU0_SB_DQS_DN<9>")
	)
	(segment
		(start 332.377288 -214.108538)
		(end 332.340458 -214.071708)
		(width 0.1524)
		(layer "F.Cu")
		(net "M_A_CPU0_SB_DQS_DN<8>")
	)
	(segment
		(start 332.7908 -220.366082)
		(end 332.605888 -220.366336)
		(width 0.088646)
		(layer "F.Cu")
		(net "M_A_CPU0_SB_DQS_DN<8>")
	)
	(segment
		(start 333.493872 -220.532198)
		(end 333.392526 -220.578426)
		(width 0.088646)
		(layer "F.Cu")
		(net "M_A_CPU0_SB_DQS_DN<8>")
	)
	(segment
		(start 307.576728 -199.448928)
		(end 307.76291 -199.448928)
		(width 0.20066)
		(layer "F.Cu")
		(net "M_A_CPU0_SB_DQS_DN<8>")
	)
	(segment
		(start 332.377288 -214.488268)
		(end 332.377288 -214.108538)
		(width 0.1524)
		(layer "F.Cu")
		(net "M_A_CPU0_SB_DQS_DN<8>")
	)
	(segment
		(start 310.088026 -199.441816)
		(end 310.253634 -199.441816)
		(width 0.20066)
		(layer "F.Cu")
		(net "M_A_CPU0_SB_DQS_DN<8>")
	)
	(segment
		(start 313.839352 -199.600566)
		(end 313.57316 -199.866758)
		(width 0.20066)
		(layer "F.Cu")
		(net "M_A_CPU0_SB_DQS_DN<8>")
	)
	(segment
		(start 312.222388 -199.605646)
		(end 312.4835 -199.866758)
		(width 0.20066)
		(layer "F.Cu")
		(net "M_A_CPU0_SB_DQS_DN<8>")
	)
	(segment
		(start 313.57316 -199.866758)
		(end 312.987182 -199.866758)
		(width 0.20066)
		(layer "F.Cu")
		(net "M_A_CPU0_SB_DQS_DN<8>")
	)
	(segment
		(start 333.017114 -220.549978)
		(end 333.016352 -220.54947)
		(width 0.088646)
		(layer "F.Cu")
		(net "M_A_CPU0_SB_DQS_DN<8>")
	)
	(segment
		(start 307.076094 -199.178926)
		(end 307.306726 -199.178926)
		(width 0.20066)
		(layer "F.Cu")
		(net "M_A_CPU0_SB_DQS_DN<8>")
	)
	(segment
		(start 311.498742 -199.605646)
		(end 312.222388 -199.605646)
		(width 0.20066)
		(layer "F.Cu")
		(net "M_A_CPU0_SB_DQS_DN<8>")
	)
	(segment
		(start 333.016352 -220.54947)
		(end 333.016098 -220.54947)
		(width 0.088646)
		(layer "F.Cu")
		(net "M_A_CPU0_SB_DQS_DN<8>")
	)
	(segment
		(start 333.016098 -220.54947)
		(end 333.014066 -220.548454)
		(width 0.088646)
		(layer "F.Cu")
		(net "M_A_CPU0_SB_DQS_DN<8>")
	)
	(segment
		(start 307.76291 -199.448928)
		(end 307.770022 -199.441816)
		(width 0.1016)
		(layer "F.Cu")
		(net "M_A_CPU0_SB_DQS_DN<8>")
	)
	(segment
		(start 306.190396 -199.605646)
		(end 306.649374 -199.605646)
		(width 0.20066)
		(layer "F.Cu")
		(net "M_A_CPU0_SB_DQS_DN<8>")
	)
	(segment
		(start 331.195172 -219.000832)
		(end 331.195172 -215.670384)
		(width 0.1524)
		(layer "F.Cu")
		(net "M_A_CPU0_SB_DQS_DN<8>")
	)
	(segment
		(start 333.02194 -220.552518)
		(end 333.020162 -220.551502)
		(width 0.088646)
		(layer "F.Cu")
		(net "M_A_CPU0_SB_DQS_DN<8>")
	)
	(segment
		(start 332.991714 -220.536008)
		(end 332.98892 -220.534484)
		(width 0.088646)
		(layer "F.Cu")
		(net "M_A_CPU0_SB_DQS_DN<8>")
	)
	(segment
		(start 331.905102 -219.710762)
		(end 331.195172 -219.000832)
		(width 0.1524)
		(layer "F.Cu")
		(net "M_A_CPU0_SB_DQS_DN<8>")
	)
	(segment
		(start 331.195172 -215.670384)
		(end 332.377288 -214.488268)
		(width 0.1524)
		(layer "F.Cu")
		(net "M_A_CPU0_SB_DQS_DN<8>")
	)
	(segment
		(start 310.504586 -199.190864)
		(end 310.877966 -199.190864)
		(width 0.20066)
		(layer "F.Cu")
		(net "M_A_CPU0_SB_DQS_DN<8>")
	)
	(segment
		(start 312.4835 -199.866758)
		(end 312.987182 -199.866758)
		(width 0.20066)
		(layer "F.Cu")
		(net "M_A_CPU0_SB_DQS_DN<8>")
	)
	(segment
		(start 333.020162 -220.551502)
		(end 333.0194 -220.550994)
		(width 0.088646)
		(layer "F.Cu")
		(net "M_A_CPU0_SB_DQS_DN<8>")
	)
	(segment
		(start 305.443382 -199.866758)
		(end 305.929284 -199.866758)
		(width 0.20066)
		(layer "F.Cu")
		(net "M_A_CPU0_SB_DQS_DN<8>")
	)
	(segment
		(start 310.877966 -199.190864)
		(end 311.498742 -199.605646)
		(width 0.20066)
		(layer "F.Cu")
		(net "M_A_CPU0_SB_DQS_DN<8>")
	)
	(segment
		(start 333.032608 -220.558106)
		(end 333.02448 -220.553788)
		(width 0.088646)
		(layer "F.Cu")
		(net "M_A_CPU0_SB_DQS_DN<8>")
	)
	(segment
		(start 333.014066 -220.548454)
		(end 333.011526 -220.54693)
		(width 0.088646)
		(layer "F.Cu")
		(net "M_A_CPU0_SB_DQS_DN<8>")
	)
	(segment
		(start 334.299306 -220.827346)
		(end 334.22336 -220.679264)
		(width 0.088646)
		(layer "F.Cu")
		(net "M_A_CPU0_SB_DQS_DN<8>")
	)
	(segment
		(start 334.22336 -220.679264)
		(end 333.933038 -220.533976)
		(width 0.088646)
		(layer "F.Cu")
		(net "M_A_CPU0_SB_DQS_DN<8>")
	)
	(segment
		(start 331.965808 -219.726256)
		(end 331.920596 -219.726256)
		(width 0.088646)
		(layer "F.Cu")
		(net "M_A_CPU0_SB_DQS_DN<8>")
	)
	(segment
		(start 332.229714 -209.652108)
		(end 322.178172 -199.600566)
		(width 0.20066)
		(layer "F.Cu")
		(net "M_A_CPU0_SB_DQS_DN<8>")
	)
	(segment
		(start 332.866238 -220.44152)
		(end 332.7908 -220.366082)
		(width 0.088646)
		(layer "F.Cu")
		(net "M_A_CPU0_SB_DQS_DN<8>")
	)
	(segment
		(start 331.920596 -219.726256)
		(end 331.905102 -219.710762)
		(width 0.088646)
		(layer "F.Cu")
		(net "M_A_CPU0_SB_DQS_DN<8>")
	)
	(segment
		(start 307.306726 -199.178926)
		(end 307.576728 -199.448928)
		(width 0.20066)
		(layer "F.Cu")
		(net "M_A_CPU0_SB_DQS_DN<8>")
	)
	(segment
		(start 322.178172 -199.600566)
		(end 313.839352 -199.600566)
		(width 0.20066)
		(layer "F.Cu")
		(net "M_A_CPU0_SB_DQS_DN<8>")
	)
	(segment
		(start 332.340458 -209.91957)
		(end 332.229714 -209.652108)
		(width 0.20066)
		(layer "F.Cu")
		(net "M_A_CPU0_SB_DQS_DN<8>")
	)
	(segment
		(start 333.02448 -220.553788)
		(end 333.02194 -220.552518)
		(width 0.088646)
		(layer "F.Cu")
		(net "M_A_CPU0_SB_DQS_DN<8>")
	)
	(segment
		(start 310.253634 -199.441816)
		(end 310.504586 -199.190864)
		(width 0.20066)
		(layer "F.Cu")
		(net "M_A_CPU0_SB_DQS_DN<8>")
	)
	(segment
		(start 333.84744 -220.513656)
		(end 333.579724 -220.513656)
		(width 0.088646)
		(layer "F.Cu")
		(net "M_A_CPU0_SB_DQS_DN<8>")
	)
	(segment
		(start 306.649374 -199.605646)
		(end 307.076094 -199.178926)
		(width 0.20066)
		(layer "F.Cu")
		(net "M_A_CPU0_SB_DQS_DN<8>")
	)
	(segment
		(start 334.30591 -220.916246)
		(end 334.299306 -220.827346)
		(width 0.088646)
		(layer "F.Cu")
		(net "M_A_CPU0_SB_DQS_DN<8>")
	)
	(segment
		(start 332.605888 -220.366336)
		(end 331.965808 -219.726256)
		(width 0.088646)
		(layer "F.Cu")
		(net "M_A_CPU0_SB_DQS_DN<8>")
	)
	(segment
		(start 307.770022 -199.441816)
		(end 310.088026 -199.441816)
		(width 0.1016)
		(layer "F.Cu")
		(net "M_A_CPU0_SB_DQS_DN<8>")
	)
	(segment
		(start 305.929284 -199.866758)
		(end 306.190396 -199.605646)
		(width 0.20066)
		(layer "F.Cu")
		(net "M_A_CPU0_SB_DQS_DN<8>")
	)
	(segment
		(start 335.244186 -220.956632)
		(end 334.862932 -221.180152)
		(width 0.088646)
		(layer "F.Cu")
		(net "M_A_CPU0_SB_DQS_DN<8>")
	)
	(segment
		(start 333.011526 -220.54693)
		(end 332.991714 -220.536008)
		(width 0.088646)
		(layer "F.Cu")
		(net "M_A_CPU0_SB_DQS_DN<8>")
	)
	(segment
		(start 332.340458 -214.071708)
		(end 332.340458 -214.033608)
		(width 0.1524)
		(layer "F.Cu")
		(net "M_A_CPU0_SB_DQS_DN<8>")
	)
	(segment
		(start 332.340458 -214.033608)
		(end 332.340458 -209.91957)
		(width 0.20066)
		(layer "F.Cu")
		(net "M_A_CPU0_SB_DQS_DN<8>")
	)
	(segment
		(start 333.0194 -220.550994)
		(end 333.017114 -220.549978)
		(width 0.088646)
		(layer "F.Cu")
		(net "M_A_CPU0_SB_DQS_DN<8>")
	)
	(arc
		(start 335.615534 -220.855794)
		(mid 335.423138 -220.881456)
		(end 335.244186 -220.956632)
		(width 0.088646)
		(layer "F.Cu")
		(net "M_A_CPU0_SB_DQS_DN<8>")
	)
	(arc
		(start 334.488536 -221.180152)
		(mid 334.367569 -221.06872)
		(end 334.30591 -220.916246)
		(width 0.088646)
		(layer "F.Cu")
		(net "M_A_CPU0_SB_DQS_DN<8>")
	)
	(arc
		(start 332.98892 -220.534484)
		(mid 332.924402 -220.492196)
		(end 332.866238 -220.44152)
		(width 0.088646)
		(layer "F.Cu")
		(net "M_A_CPU0_SB_DQS_DN<8>")
	)
	(arc
		(start 333.933038 -220.533976)
		(mid 333.891428 -220.518794)
		(end 333.84744 -220.513656)
		(width 0.088646)
		(layer "F.Cu")
		(net "M_A_CPU0_SB_DQS_DN<8>")
	)
	(arc
		(start 333.392526 -220.578426)
		(mid 333.309165 -220.60515)
		(end 333.221838 -220.611192)
		(width 0.088646)
		(layer "F.Cu")
		(net "M_A_CPU0_SB_DQS_DN<8>")
	)
	(arc
		(start 333.221838 -220.611192)
		(mid 333.124419 -220.594649)
		(end 333.032608 -220.558106)
		(width 0.088646)
		(layer "F.Cu")
		(net "M_A_CPU0_SB_DQS_DN<8>")
	)
	(arc
		(start 334.862932 -221.180152)
		(mid 334.675734 -221.230295)
		(end 334.488536 -221.180152)
		(width 0.088646)
		(layer "F.Cu")
		(net "M_A_CPU0_SB_DQS_DN<8>")
	)
	(arc
		(start 333.579724 -220.513656)
		(mid 333.535813 -220.518355)
		(end 333.493872 -220.532198)
		(width 0.088646)
		(layer "F.Cu")
		(net "M_A_CPU0_SB_DQS_DN<8>")
	)
	(segment
		(start 333.921608 -230.29672)
		(end 333.91983 -230.295704)
		(width 0.088646)
		(layer "F.Cu")
		(net "M_A_CPU0_SB_DQS_DN<7>")
	)
	(segment
		(start 332.998064 -230.30688)
		(end 332.983332 -230.298244)
		(width 0.088646)
		(layer "F.Cu")
		(net "M_A_CPU0_SB_DQS_DN<7>")
	)
	(segment
		(start 331.872082 -230.312214)
		(end 331.586078 -230.312214)
		(width 0.1524)
		(layer "F.Cu")
		(net "M_A_CPU0_SB_DQS_DN<7>")
	)
	(segment
		(start 326.526652 -223.113346)
		(end 326.526652 -216.966038)
		(width 0.1524)
		(layer "F.Cu")
		(net "M_A_CPU0_SB_DQS_DN<7>")
	)
	(segment
		(start 332.796134 -230.247698)
		(end 332.539848 -230.247698)
		(width 0.088646)
		(layer "F.Cu")
		(net "M_A_CPU0_SB_DQS_DN<7>")
	)
	(segment
		(start 334.299052 -230.59009)
		(end 334.227424 -230.449374)
		(width 0.088646)
		(layer "F.Cu")
		(net "M_A_CPU0_SB_DQS_DN<7>")
	)
	(segment
		(start 313.909202 -209.118708)
		(end 313.906408 -209.121502)
		(width 0.20066)
		(layer "F.Cu")
		(net "M_A_CPU0_SB_DQS_DN<7>")
	)
	(segment
		(start 334.300322 -230.604314)
		(end 334.299052 -230.59009)
		(width 0.088646)
		(layer "F.Cu")
		(net "M_A_CPU0_SB_DQS_DN<7>")
	)
	(segment
		(start 307.387752 -208.806542)
		(end 307.76291 -208.806542)
		(width 0.20066)
		(layer "F.Cu")
		(net "M_A_CPU0_SB_DQS_DN<7>")
	)
	(segment
		(start 326.147176 -215.664288)
		(end 319.601596 -209.118708)
		(width 0.20066)
		(layer "F.Cu")
		(net "M_A_CPU0_SB_DQS_DN<7>")
	)
	(segment
		(start 333.548482 -230.29799)
		(end 333.548736 -230.298244)
		(width 0.088646)
		(layer "F.Cu")
		(net "M_A_CPU0_SB_DQS_DN<7>")
	)
	(segment
		(start 306.971954 -208.52892)
		(end 307.11013 -208.52892)
		(width 0.20066)
		(layer "F.Cu")
		(net "M_A_CPU0_SB_DQS_DN<7>")
	)
	(segment
		(start 307.76291 -208.806542)
		(end 307.831744 -208.79181)
		(width 0.1016)
		(layer "F.Cu")
		(net "M_A_CPU0_SB_DQS_DN<7>")
	)
	(segment
		(start 305.929284 -209.216752)
		(end 306.190396 -208.95564)
		(width 0.20066)
		(layer "F.Cu")
		(net "M_A_CPU0_SB_DQS_DN<7>")
	)
	(segment
		(start 326.526652 -216.966038)
		(end 326.413114 -216.691972)
		(width 0.1524)
		(layer "F.Cu")
		(net "M_A_CPU0_SB_DQS_DN<7>")
	)
	(segment
		(start 307.831744 -208.79181)
		(end 310.073294 -208.79181)
		(width 0.1016)
		(layer "F.Cu")
		(net "M_A_CPU0_SB_DQS_DN<7>")
	)
	(segment
		(start 334.30591 -230.683054)
		(end 334.300068 -230.604314)
		(width 0.088646)
		(layer "F.Cu")
		(net "M_A_CPU0_SB_DQS_DN<7>")
	)
	(segment
		(start 334.488536 -230.94696)
		(end 334.488282 -230.946706)
		(width 0.088646)
		(layer "F.Cu")
		(net "M_A_CPU0_SB_DQS_DN<7>")
	)
	(segment
		(start 313.884056 -209.121502)
		(end 313.788806 -209.216752)
		(width 0.20066)
		(layer "F.Cu")
		(net "M_A_CPU0_SB_DQS_DN<7>")
	)
	(segment
		(start 312.222388 -208.95564)
		(end 312.4835 -209.216752)
		(width 0.20066)
		(layer "F.Cu")
		(net "M_A_CPU0_SB_DQS_DN<7>")
	)
	(segment
		(start 312.4835 -209.216752)
		(end 312.987182 -209.216752)
		(width 0.20066)
		(layer "F.Cu")
		(net "M_A_CPU0_SB_DQS_DN<7>")
	)
	(segment
		(start 326.226424 -215.691212)
		(end 326.1741 -215.691212)
		(width 0.1524)
		(layer "F.Cu")
		(net "M_A_CPU0_SB_DQS_DN<7>")
	)
	(segment
		(start 310.443626 -208.806542)
		(end 310.717184 -208.532984)
		(width 0.20066)
		(layer "F.Cu")
		(net "M_A_CPU0_SB_DQS_DN<7>")
	)
	(segment
		(start 332.539848 -230.247698)
		(end 332.507336 -230.28021)
		(width 0.088646)
		(layer "F.Cu")
		(net "M_A_CPU0_SB_DQS_DN<7>")
	)
	(segment
		(start 333.92237 -230.296974)
		(end 333.921608 -230.29672)
		(width 0.088646)
		(layer "F.Cu")
		(net "M_A_CPU0_SB_DQS_DN<7>")
	)
	(segment
		(start 313.906408 -209.121502)
		(end 313.884056 -209.121502)
		(width 0.20066)
		(layer "F.Cu")
		(net "M_A_CPU0_SB_DQS_DN<7>")
	)
	(segment
		(start 306.190396 -208.95564)
		(end 306.545234 -208.95564)
		(width 0.20066)
		(layer "F.Cu")
		(net "M_A_CPU0_SB_DQS_DN<7>")
	)
	(segment
		(start 328.131932 -224.718626)
		(end 326.526652 -223.113346)
		(width 0.1524)
		(layer "F.Cu")
		(net "M_A_CPU0_SB_DQS_DN<7>")
	)
	(segment
		(start 306.545234 -208.95564)
		(end 306.971954 -208.52892)
		(width 0.20066)
		(layer "F.Cu")
		(net "M_A_CPU0_SB_DQS_DN<7>")
	)
	(segment
		(start 326.37476 -215.839294)
		(end 326.226424 -215.691212)
		(width 0.1524)
		(layer "F.Cu")
		(net "M_A_CPU0_SB_DQS_DN<7>")
	)
	(segment
		(start 326.413114 -216.691972)
		(end 326.413114 -215.877648)
		(width 0.1524)
		(layer "F.Cu")
		(net "M_A_CPU0_SB_DQS_DN<7>")
	)
	(segment
		(start 331.586078 -230.312214)
		(end 328.131932 -226.858068)
		(width 0.1524)
		(layer "F.Cu")
		(net "M_A_CPU0_SB_DQS_DN<7>")
	)
	(segment
		(start 331.926184 -230.28021)
		(end 331.89418 -230.312214)
		(width 0.088646)
		(layer "F.Cu")
		(net "M_A_CPU0_SB_DQS_DN<7>")
	)
	(segment
		(start 319.601596 -209.118708)
		(end 313.909202 -209.118708)
		(width 0.20066)
		(layer "F.Cu")
		(net "M_A_CPU0_SB_DQS_DN<7>")
	)
	(segment
		(start 313.788806 -209.216752)
		(end 312.987182 -209.216752)
		(width 0.20066)
		(layer "F.Cu")
		(net "M_A_CPU0_SB_DQS_DN<7>")
	)
	(segment
		(start 310.073294 -208.79181)
		(end 310.088026 -208.806542)
		(width 0.1016)
		(layer "F.Cu")
		(net "M_A_CPU0_SB_DQS_DN<7>")
	)
	(segment
		(start 334.300068 -230.604314)
		(end 334.300322 -230.604314)
		(width 0.088646)
		(layer "F.Cu")
		(net "M_A_CPU0_SB_DQS_DN<7>")
	)
	(segment
		(start 311.706768 -208.95564)
		(end 312.222388 -208.95564)
		(width 0.20066)
		(layer "F.Cu")
		(net "M_A_CPU0_SB_DQS_DN<7>")
	)
	(segment
		(start 326.1741 -215.691212)
		(end 326.147176 -215.664288)
		(width 0.1524)
		(layer "F.Cu")
		(net "M_A_CPU0_SB_DQS_DN<7>")
	)
	(segment
		(start 310.717184 -208.532984)
		(end 311.074308 -208.532984)
		(width 0.20066)
		(layer "F.Cu")
		(net "M_A_CPU0_SB_DQS_DN<7>")
	)
	(segment
		(start 333.91983 -230.295704)
		(end 333.916528 -230.293926)
		(width 0.088646)
		(layer "F.Cu")
		(net "M_A_CPU0_SB_DQS_DN<7>")
	)
	(segment
		(start 310.088026 -208.806542)
		(end 310.443626 -208.806542)
		(width 0.20066)
		(layer "F.Cu")
		(net "M_A_CPU0_SB_DQS_DN<7>")
	)
	(segment
		(start 311.074308 -208.532984)
		(end 311.706768 -208.95564)
		(width 0.20066)
		(layer "F.Cu")
		(net "M_A_CPU0_SB_DQS_DN<7>")
	)
	(segment
		(start 332.507336 -230.28021)
		(end 331.926184 -230.28021)
		(width 0.088646)
		(layer "F.Cu")
		(net "M_A_CPU0_SB_DQS_DN<7>")
	)
	(segment
		(start 331.89418 -230.312214)
		(end 331.872082 -230.312214)
		(width 0.088646)
		(layer "F.Cu")
		(net "M_A_CPU0_SB_DQS_DN<7>")
	)
	(segment
		(start 305.443382 -209.216752)
		(end 305.929284 -209.216752)
		(width 0.20066)
		(layer "F.Cu")
		(net "M_A_CPU0_SB_DQS_DN<7>")
	)
	(segment
		(start 334.227424 -230.449374)
		(end 333.92237 -230.296974)
		(width 0.088646)
		(layer "F.Cu")
		(net "M_A_CPU0_SB_DQS_DN<7>")
	)
	(segment
		(start 328.131932 -226.858068)
		(end 328.131932 -224.718626)
		(width 0.1524)
		(layer "F.Cu")
		(net "M_A_CPU0_SB_DQS_DN<7>")
	)
	(segment
		(start 335.244186 -230.72344)
		(end 334.862932 -230.94696)
		(width 0.088646)
		(layer "F.Cu")
		(net "M_A_CPU0_SB_DQS_DN<7>")
	)
	(segment
		(start 307.11013 -208.52892)
		(end 307.387752 -208.806542)
		(width 0.20066)
		(layer "F.Cu")
		(net "M_A_CPU0_SB_DQS_DN<7>")
	)
	(segment
		(start 326.413114 -215.877648)
		(end 326.37476 -215.839294)
		(width 0.1524)
		(layer "F.Cu")
		(net "M_A_CPU0_SB_DQS_DN<7>")
	)
	(arc
		(start 332.983332 -230.298244)
		(mid 332.904541 -230.263943)
		(end 332.82001 -230.24846)
		(width 0.088646)
		(layer "F.Cu")
		(net "M_A_CPU0_SB_DQS_DN<7>")
	)
	(arc
		(start 334.488282 -230.946706)
		(mid 334.367468 -230.835385)
		(end 334.30591 -230.683054)
		(width 0.088646)
		(layer "F.Cu")
		(net "M_A_CPU0_SB_DQS_DN<7>")
	)
	(arc
		(start 334.862932 -230.94696)
		(mid 334.675734 -230.997103)
		(end 334.488536 -230.94696)
		(width 0.088646)
		(layer "F.Cu")
		(net "M_A_CPU0_SB_DQS_DN<7>")
	)
	(arc
		(start 333.548736 -230.298244)
		(mid 333.274537 -230.374079)
		(end 332.998064 -230.30688)
		(width 0.088646)
		(layer "F.Cu")
		(net "M_A_CPU0_SB_DQS_DN<7>")
	)
	(arc
		(start 332.82001 -230.24846)
		(mid 332.808078 -230.247889)
		(end 332.796134 -230.247698)
		(width 0.088646)
		(layer "F.Cu")
		(net "M_A_CPU0_SB_DQS_DN<7>")
	)
	(arc
		(start 335.615534 -230.622602)
		(mid 335.423138 -230.648264)
		(end 335.244186 -230.72344)
		(width 0.088646)
		(layer "F.Cu")
		(net "M_A_CPU0_SB_DQS_DN<7>")
	)
	(arc
		(start 333.916528 -230.293926)
		(mid 333.731982 -230.247725)
		(end 333.548482 -230.29799)
		(width 0.088646)
		(layer "F.Cu")
		(net "M_A_CPU0_SB_DQS_DN<7>")
	)
	(segment
		(start 311.61482 -218.32443)
		(end 312.241184 -218.32443)
		(width 0.20066)
		(layer "F.Cu")
		(net "M_A_CPU0_SB_DQS_DN<6>")
	)
	(segment
		(start 332.998064 -235.190284)
		(end 332.983332 -235.181648)
		(width 0.088646)
		(layer "F.Cu")
		(net "M_A_CPU0_SB_DQS_DN<6>")
	)
	(segment
		(start 331.91323 -235.131102)
		(end 331.824076 -235.041948)
		(width 0.088646)
		(layer "F.Cu")
		(net "M_A_CPU0_SB_DQS_DN<6>")
	)
	(segment
		(start 334.300068 -235.487718)
		(end 334.300322 -235.487718)
		(width 0.088646)
		(layer "F.Cu")
		(net "M_A_CPU0_SB_DQS_DN<6>")
	)
	(segment
		(start 333.548482 -235.181394)
		(end 333.548736 -235.181648)
		(width 0.088646)
		(layer "F.Cu")
		(net "M_A_CPU0_SB_DQS_DN<6>")
	)
	(segment
		(start 331.432662 -235.073952)
		(end 331.410564 -235.073952)
		(width 0.088646)
		(layer "F.Cu")
		(net "M_A_CPU0_SB_DQS_DN<6>")
	)
	(segment
		(start 331.824076 -235.041948)
		(end 331.464666 -235.041948)
		(width 0.088646)
		(layer "F.Cu")
		(net "M_A_CPU0_SB_DQS_DN<6>")
	)
	(segment
		(start 324.59676 -228.915468)
		(end 324.24624 -228.915468)
		(width 0.1524)
		(layer "F.Cu")
		(net "M_A_CPU0_SB_DQS_DN<6>")
	)
	(segment
		(start 332.796388 -235.131102)
		(end 331.91323 -235.131102)
		(width 0.088646)
		(layer "F.Cu")
		(net "M_A_CPU0_SB_DQS_DN<6>")
	)
	(segment
		(start 310.971692 -217.894662)
		(end 311.61482 -218.32443)
		(width 0.20066)
		(layer "F.Cu")
		(net "M_A_CPU0_SB_DQS_DN<6>")
	)
	(segment
		(start 314.575952 -218.42349)
		(end 314.2361 -218.563444)
		(width 0.20066)
		(layer "F.Cu")
		(net "M_A_CPU0_SB_DQS_DN<6>")
	)
	(segment
		(start 305.443382 -218.566746)
		(end 305.929284 -218.566746)
		(width 0.20066)
		(layer "F.Cu")
		(net "M_A_CPU0_SB_DQS_DN<6>")
	)
	(segment
		(start 331.464666 -235.041948)
		(end 331.432662 -235.073952)
		(width 0.088646)
		(layer "F.Cu")
		(net "M_A_CPU0_SB_DQS_DN<6>")
	)
	(segment
		(start 306.190396 -218.305634)
		(end 306.542694 -218.305634)
		(width 0.20066)
		(layer "F.Cu")
		(net "M_A_CPU0_SB_DQS_DN<6>")
	)
	(segment
		(start 310.070754 -218.141804)
		(end 310.079136 -218.150186)
		(width 0.1016)
		(layer "F.Cu")
		(net "M_A_CPU0_SB_DQS_DN<6>")
	)
	(segment
		(start 324.20941 -228.952298)
		(end 324.17131 -228.952298)
		(width 0.1524)
		(layer "F.Cu")
		(net "M_A_CPU0_SB_DQS_DN<6>")
	)
	(segment
		(start 312.241184 -218.32443)
		(end 312.4835 -218.566746)
		(width 0.20066)
		(layer "F.Cu")
		(net "M_A_CPU0_SB_DQS_DN<6>")
	)
	(segment
		(start 307.384704 -218.148916)
		(end 307.76291 -218.148916)
		(width 0.20066)
		(layer "F.Cu")
		(net "M_A_CPU0_SB_DQS_DN<6>")
	)
	(segment
		(start 312.4835 -218.566746)
		(end 312.987182 -218.566746)
		(width 0.20066)
		(layer "F.Cu")
		(net "M_A_CPU0_SB_DQS_DN<6>")
	)
	(segment
		(start 335.244186 -235.606844)
		(end 334.862932 -235.830364)
		(width 0.088646)
		(layer "F.Cu")
		(net "M_A_CPU0_SB_DQS_DN<6>")
	)
	(segment
		(start 319.161668 -222.095314)
		(end 315.634624 -218.56827)
		(width 0.20066)
		(layer "F.Cu")
		(net "M_A_CPU0_SB_DQS_DN<6>")
	)
	(segment
		(start 319.161668 -227.175314)
		(end 319.161668 -222.095314)
		(width 0.20066)
		(layer "F.Cu")
		(net "M_A_CPU0_SB_DQS_DN<6>")
	)
	(segment
		(start 310.079136 -218.150186)
		(end 310.088026 -218.150186)
		(width 0.1016)
		(layer "F.Cu")
		(net "M_A_CPU0_SB_DQS_DN<6>")
	)
	(segment
		(start 333.91983 -235.179108)
		(end 333.916528 -235.17733)
		(width 0.088646)
		(layer "F.Cu")
		(net "M_A_CPU0_SB_DQS_DN<6>")
	)
	(segment
		(start 320.938652 -228.952298)
		(end 319.161668 -227.175314)
		(width 0.20066)
		(layer "F.Cu")
		(net "M_A_CPU0_SB_DQS_DN<6>")
	)
	(segment
		(start 315.634624 -218.56827)
		(end 315.285374 -218.42349)
		(width 0.20066)
		(layer "F.Cu")
		(net "M_A_CPU0_SB_DQS_DN<6>")
	)
	(segment
		(start 307.770022 -218.141804)
		(end 310.070754 -218.141804)
		(width 0.1016)
		(layer "F.Cu")
		(net "M_A_CPU0_SB_DQS_DN<6>")
	)
	(segment
		(start 333.921608 -235.180124)
		(end 333.91983 -235.179108)
		(width 0.088646)
		(layer "F.Cu")
		(net "M_A_CPU0_SB_DQS_DN<6>")
	)
	(segment
		(start 333.92237 -235.180378)
		(end 333.921608 -235.180124)
		(width 0.088646)
		(layer "F.Cu")
		(net "M_A_CPU0_SB_DQS_DN<6>")
	)
	(segment
		(start 331.410564 -235.073952)
		(end 330.755244 -235.073952)
		(width 0.1524)
		(layer "F.Cu")
		(net "M_A_CPU0_SB_DQS_DN<6>")
	)
	(segment
		(start 324.24624 -228.915468)
		(end 324.20941 -228.952298)
		(width 0.1524)
		(layer "F.Cu")
		(net "M_A_CPU0_SB_DQS_DN<6>")
	)
	(segment
		(start 310.088026 -218.150186)
		(end 310.412384 -218.150186)
		(width 0.20066)
		(layer "F.Cu")
		(net "M_A_CPU0_SB_DQS_DN<6>")
	)
	(segment
		(start 310.667908 -217.894662)
		(end 310.971692 -217.894662)
		(width 0.20066)
		(layer "F.Cu")
		(net "M_A_CPU0_SB_DQS_DN<6>")
	)
	(segment
		(start 330.755244 -235.073952)
		(end 324.59676 -228.915468)
		(width 0.1524)
		(layer "F.Cu")
		(net "M_A_CPU0_SB_DQS_DN<6>")
	)
	(segment
		(start 315.285374 -218.42349)
		(end 314.575952 -218.42349)
		(width 0.20066)
		(layer "F.Cu")
		(net "M_A_CPU0_SB_DQS_DN<6>")
	)
	(segment
		(start 313.7154 -218.566746)
		(end 312.987182 -218.566746)
		(width 0.20066)
		(layer "F.Cu")
		(net "M_A_CPU0_SB_DQS_DN<6>")
	)
	(segment
		(start 307.76291 -218.148916)
		(end 307.770022 -218.141804)
		(width 0.1016)
		(layer "F.Cu")
		(net "M_A_CPU0_SB_DQS_DN<6>")
	)
	(segment
		(start 324.17131 -228.952298)
		(end 320.938652 -228.952298)
		(width 0.20066)
		(layer "F.Cu")
		(net "M_A_CPU0_SB_DQS_DN<6>")
	)
	(segment
		(start 313.718702 -218.563444)
		(end 313.7154 -218.566746)
		(width 0.20066)
		(layer "F.Cu")
		(net "M_A_CPU0_SB_DQS_DN<6>")
	)
	(segment
		(start 314.2361 -218.563444)
		(end 313.718702 -218.563444)
		(width 0.20066)
		(layer "F.Cu")
		(net "M_A_CPU0_SB_DQS_DN<6>")
	)
	(segment
		(start 310.412384 -218.150186)
		(end 310.667908 -217.894662)
		(width 0.20066)
		(layer "F.Cu")
		(net "M_A_CPU0_SB_DQS_DN<6>")
	)
	(segment
		(start 307.114702 -217.878914)
		(end 307.384704 -218.148916)
		(width 0.20066)
		(layer "F.Cu")
		(net "M_A_CPU0_SB_DQS_DN<6>")
	)
	(segment
		(start 334.299052 -235.473494)
		(end 334.227424 -235.332778)
		(width 0.088646)
		(layer "F.Cu")
		(net "M_A_CPU0_SB_DQS_DN<6>")
	)
	(segment
		(start 306.542694 -218.305634)
		(end 306.969414 -217.878914)
		(width 0.20066)
		(layer "F.Cu")
		(net "M_A_CPU0_SB_DQS_DN<6>")
	)
	(segment
		(start 334.227424 -235.332778)
		(end 333.92237 -235.180378)
		(width 0.088646)
		(layer "F.Cu")
		(net "M_A_CPU0_SB_DQS_DN<6>")
	)
	(segment
		(start 334.300322 -235.487718)
		(end 334.299052 -235.473494)
		(width 0.088646)
		(layer "F.Cu")
		(net "M_A_CPU0_SB_DQS_DN<6>")
	)
	(segment
		(start 306.969414 -217.878914)
		(end 307.114702 -217.878914)
		(width 0.20066)
		(layer "F.Cu")
		(net "M_A_CPU0_SB_DQS_DN<6>")
	)
	(segment
		(start 334.30591 -235.566458)
		(end 334.300068 -235.487718)
		(width 0.088646)
		(layer "F.Cu")
		(net "M_A_CPU0_SB_DQS_DN<6>")
	)
	(segment
		(start 305.929284 -218.566746)
		(end 306.190396 -218.305634)
		(width 0.20066)
		(layer "F.Cu")
		(net "M_A_CPU0_SB_DQS_DN<6>")
	)
	(arc
		(start 334.488536 -235.830364)
		(mid 334.367569 -235.718932)
		(end 334.30591 -235.566458)
		(width 0.088646)
		(layer "F.Cu")
		(net "M_A_CPU0_SB_DQS_DN<6>")
	)
	(arc
		(start 333.916528 -235.17733)
		(mid 333.731982 -235.131129)
		(end 333.548482 -235.181394)
		(width 0.088646)
		(layer "F.Cu")
		(net "M_A_CPU0_SB_DQS_DN<6>")
	)
	(arc
		(start 332.983332 -235.181648)
		(mid 332.904541 -235.147347)
		(end 332.82001 -235.131864)
		(width 0.088646)
		(layer "F.Cu")
		(net "M_A_CPU0_SB_DQS_DN<6>")
	)
	(arc
		(start 333.5274 -235.193332)
		(mid 333.262343 -235.25762)
		(end 332.998064 -235.190284)
		(width 0.088646)
		(layer "F.Cu")
		(net "M_A_CPU0_SB_DQS_DN<6>")
	)
	(arc
		(start 333.548736 -235.181648)
		(mid 333.538131 -235.187605)
		(end 333.5274 -235.193332)
		(width 0.088646)
		(layer "F.Cu")
		(net "M_A_CPU0_SB_DQS_DN<6>")
	)
	(arc
		(start 332.82001 -235.131864)
		(mid 332.808205 -235.131297)
		(end 332.796388 -235.131102)
		(width 0.088646)
		(layer "F.Cu")
		(net "M_A_CPU0_SB_DQS_DN<6>")
	)
	(arc
		(start 334.862932 -235.830364)
		(mid 334.675734 -235.880507)
		(end 334.488536 -235.830364)
		(width 0.088646)
		(layer "F.Cu")
		(net "M_A_CPU0_SB_DQS_DN<6>")
	)
	(arc
		(start 335.615534 -235.506006)
		(mid 335.423138 -235.531668)
		(end 335.244186 -235.606844)
		(width 0.088646)
		(layer "F.Cu")
		(net "M_A_CPU0_SB_DQS_DN<6>")
	)
	(segment
		(start 311.030366 -227.255578)
		(end 310.489854 -227.255578)
		(width 0.20066)
		(layer "F.Cu")
		(net "M_A_CPU0_SB_DQS_DN<5>")
	)
	(segment
		(start 310.253634 -227.491798)
		(end 310.088026 -227.491798)
		(width 0.20066)
		(layer "F.Cu")
		(net "M_A_CPU0_SB_DQS_DN<5>")
	)
	(segment
		(start 305.929284 -227.91674)
		(end 305.443382 -227.91674)
		(width 0.20066)
		(layer "F.Cu")
		(net "M_A_CPU0_SB_DQS_DN<5>")
	)
	(segment
		(start 312.4835 -227.91674)
		(end 312.222388 -227.655628)
		(width 0.20066)
		(layer "F.Cu")
		(net "M_A_CPU0_SB_DQS_DN<5>")
	)
	(segment
		(start 310.088026 -227.491798)
		(end 308.104286 -227.491798)
		(width 0.1016)
		(layer "F.Cu")
		(net "M_A_CPU0_SB_DQS_DN<5>")
	)
	(segment
		(start 337.96478 -237.947454)
		(end 337.96478 -237.411768)
		(width 0.20066)
		(layer "F.Cu")
		(net "M_A_CPU0_SB_DQS_DN<5>")
	)
	(segment
		(start 307.585364 -227.514658)
		(end 307.307234 -227.236528)
		(width 0.20066)
		(layer "F.Cu")
		(net "M_A_CPU0_SB_DQS_DN<5>")
	)
	(segment
		(start 306.649374 -227.655628)
		(end 306.190396 -227.655628)
		(width 0.20066)
		(layer "F.Cu")
		(net "M_A_CPU0_SB_DQS_DN<5>")
	)
	(segment
		(start 307.068474 -227.236528)
		(end 306.649374 -227.655628)
		(width 0.20066)
		(layer "F.Cu")
		(net "M_A_CPU0_SB_DQS_DN<5>")
	)
	(segment
		(start 314.092082 -227.91674)
		(end 312.987182 -227.91674)
		(width 0.20066)
		(layer "F.Cu")
		(net "M_A_CPU0_SB_DQS_DN<5>")
	)
	(segment
		(start 312.222388 -227.655628)
		(end 311.629298 -227.655628)
		(width 0.20066)
		(layer "F.Cu")
		(net "M_A_CPU0_SB_DQS_DN<5>")
	)
	(segment
		(start 308.104286 -227.491798)
		(end 307.78577 -227.491798)
		(width 0.101854)
		(layer "F.Cu")
		(net "M_A_CPU0_SB_DQS_DN<5>")
	)
	(segment
		(start 312.987182 -227.91674)
		(end 312.4835 -227.91674)
		(width 0.20066)
		(layer "F.Cu")
		(net "M_A_CPU0_SB_DQS_DN<5>")
	)
	(segment
		(start 337.96478 -237.411768)
		(end 337.965034 -237.411514)
		(width 0.20066)
		(layer "F.Cu")
		(net "M_A_CPU0_SB_DQS_DN<5>")
	)
	(segment
		(start 307.307234 -227.236528)
		(end 307.068474 -227.236528)
		(width 0.20066)
		(layer "F.Cu")
		(net "M_A_CPU0_SB_DQS_DN<5>")
	)
	(segment
		(start 311.629298 -227.655628)
		(end 311.030366 -227.255578)
		(width 0.20066)
		(layer "F.Cu")
		(net "M_A_CPU0_SB_DQS_DN<5>")
	)
	(segment
		(start 307.78577 -227.491798)
		(end 307.76291 -227.514658)
		(width 0.101854)
		(layer "F.Cu")
		(net "M_A_CPU0_SB_DQS_DN<5>")
	)
	(segment
		(start 307.76291 -227.514658)
		(end 307.585364 -227.514658)
		(width 0.20066)
		(layer "F.Cu")
		(net "M_A_CPU0_SB_DQS_DN<5>")
	)
	(segment
		(start 306.190396 -227.655628)
		(end 305.929284 -227.91674)
		(width 0.20066)
		(layer "F.Cu")
		(net "M_A_CPU0_SB_DQS_DN<5>")
	)
	(segment
		(start 310.489854 -227.255578)
		(end 310.253634 -227.491798)
		(width 0.20066)
		(layer "F.Cu")
		(net "M_A_CPU0_SB_DQS_DN<5>")
	)
	(segment
		(start 328.109072 -237.227872)
		(end 326.56653 -235.68533)
		(width 0.18288)
		(layer "In2.Cu")
		(net "M_A_CPU0_SB_DQS_DN<5>")
	)
	(segment
		(start 331.795374 -237.168182)
		(end 330.792328 -237.168182)
		(width 0.088646)
		(layer "In2.Cu")
		(net "M_A_CPU0_SB_DQS_DN<5>")
	)
	(segment
		(start 338.277962 -237.411514)
		(end 338.335112 -237.354364)
		(width 0.088646)
		(layer "In2.Cu")
		(net "M_A_CPU0_SB_DQS_DN<5>")
	)
	(segment
		(start 332.150466 -237.080044)
		(end 332.14945 -237.080298)
		(width 0.088646)
		(layer "In2.Cu")
		(net "M_A_CPU0_SB_DQS_DN<5>")
	)
	(segment
		(start 334.958182 -237.08741)
		(end 334.947768 -237.093506)
		(width 0.088646)
		(layer "In2.Cu")
		(net "M_A_CPU0_SB_DQS_DN<5>")
	)
	(segment
		(start 334.018636 -237.08741)
		(end 334.008222 -237.093506)
		(width 0.088646)
		(layer "In2.Cu")
		(net "M_A_CPU0_SB_DQS_DN<5>")
	)
	(segment
		(start 326.390508 -235.68533)
		(end 326.002142 -235.296964)
		(width 0.18288)
		(layer "In2.Cu")
		(net "M_A_CPU0_SB_DQS_DN<5>")
	)
	(segment
		(start 318.535812 -227.654612)
		(end 317.744094 -227.654612)
		(width 0.18288)
		(layer "In2.Cu")
		(net "M_A_CPU0_SB_DQS_DN<5>")
	)
	(segment
		(start 330.792328 -237.168182)
		(end 330.732638 -237.227872)
		(width 0.088646)
		(layer "In2.Cu")
		(net "M_A_CPU0_SB_DQS_DN<5>")
	)
	(segment
		(start 314.35421 -227.654612)
		(end 314.092082 -227.91674)
		(width 0.18288)
		(layer "In2.Cu")
		(net "M_A_CPU0_SB_DQS_DN<5>")
	)
	(segment
		(start 316.397894 -227.654612)
		(end 316.273434 -227.779072)
		(width 0.18288)
		(layer "In2.Cu")
		(net "M_A_CPU0_SB_DQS_DN<5>")
	)
	(segment
		(start 337.227164 -237.096046)
		(end 337.212432 -237.08741)
		(width 0.088646)
		(layer "In2.Cu")
		(net "M_A_CPU0_SB_DQS_DN<5>")
	)
	(segment
		(start 316.273434 -227.779072)
		(end 315.724794 -227.779072)
		(width 0.18288)
		(layer "In2.Cu")
		(net "M_A_CPU0_SB_DQS_DN<5>")
	)
	(segment
		(start 338.161122 -237.092236)
		(end 338.152232 -237.08741)
		(width 0.088646)
		(layer "In2.Cu")
		(net "M_A_CPU0_SB_DQS_DN<5>")
	)
	(segment
		(start 317.070994 -227.779072)
		(end 316.946534 -227.654612)
		(width 0.18288)
		(layer "In2.Cu")
		(net "M_A_CPU0_SB_DQS_DN<5>")
	)
	(segment
		(start 317.619634 -227.779072)
		(end 317.070994 -227.779072)
		(width 0.18288)
		(layer "In2.Cu")
		(net "M_A_CPU0_SB_DQS_DN<5>")
	)
	(segment
		(start 333.078582 -237.08741)
		(end 333.06385 -237.096046)
		(width 0.088646)
		(layer "In2.Cu")
		(net "M_A_CPU0_SB_DQS_DN<5>")
	)
	(segment
		(start 335.898236 -237.08741)
		(end 335.887822 -237.093506)
		(width 0.088646)
		(layer "In2.Cu")
		(net "M_A_CPU0_SB_DQS_DN<5>")
	)
	(segment
		(start 315.724794 -227.779072)
		(end 315.600334 -227.654612)
		(width 0.18288)
		(layer "In2.Cu")
		(net "M_A_CPU0_SB_DQS_DN<5>")
	)
	(segment
		(start 326.56653 -235.68533)
		(end 326.390508 -235.68533)
		(width 0.18288)
		(layer "In2.Cu")
		(net "M_A_CPU0_SB_DQS_DN<5>")
	)
	(segment
		(start 330.732638 -237.227872)
		(end 328.109072 -237.227872)
		(width 0.18288)
		(layer "In2.Cu")
		(net "M_A_CPU0_SB_DQS_DN<5>")
	)
	(segment
		(start 326.002142 -235.296964)
		(end 326.002142 -235.120942)
		(width 0.18288)
		(layer "In2.Cu")
		(net "M_A_CPU0_SB_DQS_DN<5>")
	)
	(segment
		(start 326.002142 -235.120942)
		(end 318.535812 -227.654612)
		(width 0.18288)
		(layer "In2.Cu")
		(net "M_A_CPU0_SB_DQS_DN<5>")
	)
	(segment
		(start 316.946534 -227.654612)
		(end 316.397894 -227.654612)
		(width 0.18288)
		(layer "In2.Cu")
		(net "M_A_CPU0_SB_DQS_DN<5>")
	)
	(segment
		(start 317.744094 -227.654612)
		(end 317.619634 -227.779072)
		(width 0.18288)
		(layer "In2.Cu")
		(net "M_A_CPU0_SB_DQS_DN<5>")
	)
	(segment
		(start 337.965034 -237.411514)
		(end 338.277962 -237.411514)
		(width 0.088646)
		(layer "In2.Cu")
		(net "M_A_CPU0_SB_DQS_DN<5>")
	)
	(segment
		(start 315.600334 -227.654612)
		(end 314.35421 -227.654612)
		(width 0.18288)
		(layer "In2.Cu")
		(net "M_A_CPU0_SB_DQS_DN<5>")
	)
	(arc
		(start 336.838036 -237.08741)
		(mid 336.555334 -237.163186)
		(end 336.272632 -237.08741)
		(width 0.088646)
		(layer "In2.Cu")
		(net "M_A_CPU0_SB_DQS_DN<5>")
	)
	(arc
		(start 333.452978 -237.08741)
		(mid 333.26578 -237.037267)
		(end 333.078582 -237.08741)
		(width 0.088646)
		(layer "In2.Cu")
		(net "M_A_CPU0_SB_DQS_DN<5>")
	)
	(arc
		(start 333.06385 -237.096046)
		(mid 332.787375 -237.163366)
		(end 332.513178 -237.08741)
		(width 0.088646)
		(layer "In2.Cu")
		(net "M_A_CPU0_SB_DQS_DN<5>")
	)
	(arc
		(start 335.887822 -237.093506)
		(mid 335.60939 -237.163352)
		(end 335.332578 -237.08741)
		(width 0.088646)
		(layer "In2.Cu")
		(net "M_A_CPU0_SB_DQS_DN<5>")
	)
	(arc
		(start 336.272632 -237.08741)
		(mid 336.085434 -237.037233)
		(end 335.898236 -237.08741)
		(width 0.088646)
		(layer "In2.Cu")
		(net "M_A_CPU0_SB_DQS_DN<5>")
	)
	(arc
		(start 334.393032 -237.08741)
		(mid 334.205834 -237.037267)
		(end 334.018636 -237.08741)
		(width 0.088646)
		(layer "In2.Cu")
		(net "M_A_CPU0_SB_DQS_DN<5>")
	)
	(arc
		(start 332.261464 -237.042198)
		(mid 332.204474 -237.056749)
		(end 332.150466 -237.080044)
		(width 0.088646)
		(layer "In2.Cu")
		(net "M_A_CPU0_SB_DQS_DN<5>")
	)
	(arc
		(start 338.152232 -237.08741)
		(mid 337.965034 -237.037233)
		(end 337.777836 -237.08741)
		(width 0.088646)
		(layer "In2.Cu")
		(net "M_A_CPU0_SB_DQS_DN<5>")
	)
	(arc
		(start 332.513178 -237.08741)
		(mid 332.391294 -237.042671)
		(end 332.261464 -237.042198)
		(width 0.088646)
		(layer "In2.Cu")
		(net "M_A_CPU0_SB_DQS_DN<5>")
	)
	(arc
		(start 335.332578 -237.08741)
		(mid 335.14538 -237.037267)
		(end 334.958182 -237.08741)
		(width 0.088646)
		(layer "In2.Cu")
		(net "M_A_CPU0_SB_DQS_DN<5>")
	)
	(arc
		(start 337.212432 -237.08741)
		(mid 337.025234 -237.037233)
		(end 336.838036 -237.08741)
		(width 0.088646)
		(layer "In2.Cu")
		(net "M_A_CPU0_SB_DQS_DN<5>")
	)
	(arc
		(start 337.777836 -237.08741)
		(mid 337.503637 -237.163245)
		(end 337.227164 -237.096046)
		(width 0.088646)
		(layer "In2.Cu")
		(net "M_A_CPU0_SB_DQS_DN<5>")
	)
	(arc
		(start 334.947768 -237.093506)
		(mid 334.66959 -237.163229)
		(end 334.393032 -237.08741)
		(width 0.088646)
		(layer "In2.Cu")
		(net "M_A_CPU0_SB_DQS_DN<5>")
	)
	(arc
		(start 332.14945 -237.080298)
		(mid 331.977796 -237.145923)
		(end 331.795374 -237.168182)
		(width 0.088646)
		(layer "In2.Cu")
		(net "M_A_CPU0_SB_DQS_DN<5>")
	)
	(arc
		(start 334.008222 -237.093506)
		(mid 333.72979 -237.163352)
		(end 333.452978 -237.08741)
		(width 0.088646)
		(layer "In2.Cu")
		(net "M_A_CPU0_SB_DQS_DN<5>")
	)
	(arc
		(start 338.335112 -237.354364)
		(mid 338.276993 -237.204123)
		(end 338.161122 -237.092236)
		(width 0.088646)
		(layer "In2.Cu")
		(net "M_A_CPU0_SB_DQS_DN<5>")
	)
	(segment
		(start 307.142896 -236.578902)
		(end 307.306726 -236.578902)
		(width 0.20066)
		(layer "F.Cu")
		(net "M_A_CPU0_SB_DQS_DN<4>")
	)
	(segment
		(start 311.706768 -237.005622)
		(end 312.222388 -237.005622)
		(width 0.20066)
		(layer "F.Cu")
		(net "M_A_CPU0_SB_DQS_DN<4>")
	)
	(segment
		(start 323.31533 -237.848648)
		(end 323.114416 -237.647734)
		(width 0.20066)
		(layer "F.Cu")
		(net "M_A_CPU0_SB_DQS_DN<4>")
	)
	(segment
		(start 331.098144 -239.587786)
		(end 331.08265 -239.572292)
		(width 0.088646)
		(layer "F.Cu")
		(net "M_A_CPU0_SB_DQS_DN<4>")
	)
	(segment
		(start 307.02885 -236.626146)
		(end 307.142896 -236.578902)
		(width 0.20066)
		(layer "F.Cu")
		(net "M_A_CPU0_SB_DQS_DN<4>")
	)
	(segment
		(start 332.796134 -240.014252)
		(end 332.053184 -240.014252)
		(width 0.088646)
		(layer "F.Cu")
		(net "M_A_CPU0_SB_DQS_DN<4>")
	)
	(segment
		(start 334.488536 -240.713514)
		(end 334.488536 -240.71326)
		(width 0.088646)
		(layer "F.Cu")
		(net "M_A_CPU0_SB_DQS_DN<4>")
	)
	(segment
		(start 335.244186 -240.489994)
		(end 334.862932 -240.713514)
		(width 0.088646)
		(layer "F.Cu")
		(net "M_A_CPU0_SB_DQS_DN<4>")
	)
	(segment
		(start 306.649374 -237.005622)
		(end 307.02885 -236.626146)
		(width 0.20066)
		(layer "F.Cu")
		(net "M_A_CPU0_SB_DQS_DN<4>")
	)
	(segment
		(start 328.996294 -239.30483)
		(end 328.959464 -239.34166)
		(width 0.1524)
		(layer "F.Cu")
		(net "M_A_CPU0_SB_DQS_DN<4>")
	)
	(segment
		(start 334.227424 -240.215928)
		(end 333.92237 -240.063528)
		(width 0.088646)
		(layer "F.Cu")
		(net "M_A_CPU0_SB_DQS_DN<4>")
	)
	(segment
		(start 331.36459 -239.80902)
		(end 331.143356 -239.587786)
		(width 0.088646)
		(layer "F.Cu")
		(net "M_A_CPU0_SB_DQS_DN<4>")
	)
	(segment
		(start 313.2582 -237.266734)
		(end 312.987182 -237.266734)
		(width 0.20066)
		(layer "F.Cu")
		(net "M_A_CPU0_SB_DQS_DN<4>")
	)
	(segment
		(start 322.798186 -237.647734)
		(end 322.597272 -237.848648)
		(width 0.20066)
		(layer "F.Cu")
		(net "M_A_CPU0_SB_DQS_DN<4>")
	)
	(segment
		(start 312.4835 -237.266734)
		(end 312.987182 -237.266734)
		(width 0.20066)
		(layer "F.Cu")
		(net "M_A_CPU0_SB_DQS_DN<4>")
	)
	(segment
		(start 328.959464 -239.34166)
		(end 328.921364 -239.34166)
		(width 0.1524)
		(layer "F.Cu")
		(net "M_A_CPU0_SB_DQS_DN<4>")
	)
	(segment
		(start 328.921364 -239.34166)
		(end 323.638164 -239.34166)
		(width 0.20066)
		(layer "F.Cu")
		(net "M_A_CPU0_SB_DQS_DN<4>")
	)
	(segment
		(start 313.885834 -237.26648)
		(end 313.258454 -237.26648)
		(width 0.20066)
		(layer "F.Cu")
		(net "M_A_CPU0_SB_DQS_DN<4>")
	)
	(segment
		(start 315.950092 -237.237524)
		(end 313.91479 -237.237524)
		(width 0.20066)
		(layer "F.Cu")
		(net "M_A_CPU0_SB_DQS_DN<4>")
	)
	(segment
		(start 322.597272 -237.848648)
		(end 322.597272 -238.253016)
		(width 0.20066)
		(layer "F.Cu")
		(net "M_A_CPU0_SB_DQS_DN<4>")
	)
	(segment
		(start 312.222388 -237.005622)
		(end 312.4835 -237.266734)
		(width 0.20066)
		(layer "F.Cu")
		(net "M_A_CPU0_SB_DQS_DN<4>")
	)
	(segment
		(start 307.638958 -236.841792)
		(end 310.34482 -236.841792)
		(width 0.1016)
		(layer "F.Cu")
		(net "M_A_CPU0_SB_DQS_DN<4>")
	)
	(segment
		(start 311.074308 -236.582966)
		(end 311.706768 -237.005622)
		(width 0.20066)
		(layer "F.Cu")
		(net "M_A_CPU0_SB_DQS_DN<4>")
	)
	(segment
		(start 305.443382 -237.266734)
		(end 305.929284 -237.266734)
		(width 0.20066)
		(layer "F.Cu")
		(net "M_A_CPU0_SB_DQS_DN<4>")
	)
	(segment
		(start 307.569616 -236.841792)
		(end 307.638958 -236.841792)
		(width 0.20066)
		(layer "F.Cu")
		(net "M_A_CPU0_SB_DQS_DN<4>")
	)
	(segment
		(start 310.34482 -236.841792)
		(end 310.458358 -236.841792)
		(width 0.20066)
		(layer "F.Cu")
		(net "M_A_CPU0_SB_DQS_DN<4>")
	)
	(segment
		(start 305.929284 -237.266734)
		(end 306.190396 -237.005622)
		(width 0.20066)
		(layer "F.Cu")
		(net "M_A_CPU0_SB_DQS_DN<4>")
	)
	(segment
		(start 331.521816 -239.80902)
		(end 331.36459 -239.80902)
		(width 0.088646)
		(layer "F.Cu")
		(net "M_A_CPU0_SB_DQS_DN<4>")
	)
	(segment
		(start 310.458358 -236.841792)
		(end 310.717184 -236.582966)
		(width 0.20066)
		(layer "F.Cu")
		(net "M_A_CPU0_SB_DQS_DN<4>")
	)
	(segment
		(start 313.91479 -237.237524)
		(end 313.885834 -237.26648)
		(width 0.20066)
		(layer "F.Cu")
		(net "M_A_CPU0_SB_DQS_DN<4>")
	)
	(segment
		(start 331.08265 -239.572292)
		(end 330.815188 -239.30483)
		(width 0.1524)
		(layer "F.Cu")
		(net "M_A_CPU0_SB_DQS_DN<4>")
	)
	(segment
		(start 321.750436 -238.551466)
		(end 319.68567 -237.696248)
		(width 0.20066)
		(layer "F.Cu")
		(net "M_A_CPU0_SB_DQS_DN<4>")
	)
	(segment
		(start 334.299052 -240.356644)
		(end 334.227424 -240.215928)
		(width 0.088646)
		(layer "F.Cu")
		(net "M_A_CPU0_SB_DQS_DN<4>")
	)
	(segment
		(start 331.645768 -239.932972)
		(end 331.521816 -239.80902)
		(width 0.088646)
		(layer "F.Cu")
		(net "M_A_CPU0_SB_DQS_DN<4>")
	)
	(segment
		(start 323.31533 -239.018826)
		(end 323.31533 -237.848648)
		(width 0.20066)
		(layer "F.Cu")
		(net "M_A_CPU0_SB_DQS_DN<4>")
	)
	(segment
		(start 322.298822 -238.551466)
		(end 321.750436 -238.551466)
		(width 0.20066)
		(layer "F.Cu")
		(net "M_A_CPU0_SB_DQS_DN<4>")
	)
	(segment
		(start 330.815188 -239.30483)
		(end 328.996294 -239.30483)
		(width 0.1524)
		(layer "F.Cu")
		(net "M_A_CPU0_SB_DQS_DN<4>")
	)
	(segment
		(start 306.190396 -237.005622)
		(end 306.649374 -237.005622)
		(width 0.20066)
		(layer "F.Cu")
		(net "M_A_CPU0_SB_DQS_DN<4>")
	)
	(segment
		(start 307.306726 -236.578902)
		(end 307.569616 -236.841792)
		(width 0.20066)
		(layer "F.Cu")
		(net "M_A_CPU0_SB_DQS_DN<4>")
	)
	(segment
		(start 334.301084 -240.389156)
		(end 334.299052 -240.356644)
		(width 0.088646)
		(layer "F.Cu")
		(net "M_A_CPU0_SB_DQS_DN<4>")
	)
	(segment
		(start 333.91983 -240.062258)
		(end 333.916528 -240.06048)
		(width 0.088646)
		(layer "F.Cu")
		(net "M_A_CPU0_SB_DQS_DN<4>")
	)
	(segment
		(start 319.68567 -237.696248)
		(end 316.408816 -237.696248)
		(width 0.20066)
		(layer "F.Cu")
		(net "M_A_CPU0_SB_DQS_DN<4>")
	)
	(segment
		(start 333.548482 -240.064544)
		(end 333.548736 -240.064798)
		(width 0.088646)
		(layer "F.Cu")
		(net "M_A_CPU0_SB_DQS_DN<4>")
	)
	(segment
		(start 332.998064 -240.073434)
		(end 332.983332 -240.064798)
		(width 0.088646)
		(layer "F.Cu")
		(net "M_A_CPU0_SB_DQS_DN<4>")
	)
	(segment
		(start 322.597272 -238.253016)
		(end 322.298822 -238.551466)
		(width 0.20066)
		(layer "F.Cu")
		(net "M_A_CPU0_SB_DQS_DN<4>")
	)
	(segment
		(start 323.638164 -239.34166)
		(end 323.31533 -239.018826)
		(width 0.20066)
		(layer "F.Cu")
		(net "M_A_CPU0_SB_DQS_DN<4>")
	)
	(segment
		(start 310.717184 -236.582966)
		(end 311.074308 -236.582966)
		(width 0.20066)
		(layer "F.Cu")
		(net "M_A_CPU0_SB_DQS_DN<4>")
	)
	(segment
		(start 313.258454 -237.26648)
		(end 313.2582 -237.266734)
		(width 0.20066)
		(layer "F.Cu")
		(net "M_A_CPU0_SB_DQS_DN<4>")
	)
	(segment
		(start 316.408816 -237.696248)
		(end 315.950092 -237.237524)
		(width 0.20066)
		(layer "F.Cu")
		(net "M_A_CPU0_SB_DQS_DN<4>")
	)
	(segment
		(start 333.921608 -240.063274)
		(end 333.91983 -240.062258)
		(width 0.088646)
		(layer "F.Cu")
		(net "M_A_CPU0_SB_DQS_DN<4>")
	)
	(segment
		(start 323.114416 -237.647734)
		(end 322.798186 -237.647734)
		(width 0.20066)
		(layer "F.Cu")
		(net "M_A_CPU0_SB_DQS_DN<4>")
	)
	(segment
		(start 331.143356 -239.587786)
		(end 331.098144 -239.587786)
		(width 0.088646)
		(layer "F.Cu")
		(net "M_A_CPU0_SB_DQS_DN<4>")
	)
	(segment
		(start 333.92237 -240.063528)
		(end 333.921608 -240.063274)
		(width 0.088646)
		(layer "F.Cu")
		(net "M_A_CPU0_SB_DQS_DN<4>")
	)
	(arc
		(start 333.548736 -240.064798)
		(mid 333.274537 -240.140633)
		(end 332.998064 -240.073434)
		(width 0.088646)
		(layer "F.Cu")
		(net "M_A_CPU0_SB_DQS_DN<4>")
	)
	(arc
		(start 333.916528 -240.06048)
		(mid 333.731982 -240.014279)
		(end 333.548482 -240.064544)
		(width 0.088646)
		(layer "F.Cu")
		(net "M_A_CPU0_SB_DQS_DN<4>")
	)
	(arc
		(start 334.488536 -240.71326)
		(mid 334.351396 -240.576321)
		(end 334.301084 -240.389156)
		(width 0.088646)
		(layer "F.Cu")
		(net "M_A_CPU0_SB_DQS_DN<4>")
	)
	(arc
		(start 334.862932 -240.713514)
		(mid 334.675734 -240.763657)
		(end 334.488536 -240.713514)
		(width 0.088646)
		(layer "F.Cu")
		(net "M_A_CPU0_SB_DQS_DN<4>")
	)
	(arc
		(start 332.053184 -240.014252)
		(mid 331.845472 -239.993684)
		(end 331.645768 -239.932972)
		(width 0.088646)
		(layer "F.Cu")
		(net "M_A_CPU0_SB_DQS_DN<4>")
	)
	(arc
		(start 332.983332 -240.064798)
		(mid 332.89306 -240.027199)
		(end 332.796134 -240.014252)
		(width 0.088646)
		(layer "F.Cu")
		(net "M_A_CPU0_SB_DQS_DN<4>")
	)
	(arc
		(start 335.615534 -240.389156)
		(mid 335.423138 -240.414818)
		(end 335.244186 -240.489994)
		(width 0.088646)
		(layer "F.Cu")
		(net "M_A_CPU0_SB_DQS_DN<4>")
	)
	(segment
		(start 311.946544 -200.2917)
		(end 311.929526 -200.274682)
		(width 0.1016)
		(layer "F.Cu")
		(net "M_A_CPU0_SB_DQS_DN<3>")
	)
	(segment
		(start 331.654404 -214.098378)
		(end 331.700124 -214.052658)
		(width 0.1524)
		(layer "F.Cu")
		(net "M_A_CPU0_SB_DQS_DN<3>")
	)
	(segment
		(start 330.839572 -215.52154)
		(end 331.654404 -214.706708)
		(width 0.1524)
		(layer "F.Cu")
		(net "M_A_CPU0_SB_DQS_DN<3>")
	)
	(segment
		(start 329.737974 -208.06537)
		(end 329.561952 -208.06537)
		(width 0.20066)
		(layer "F.Cu")
		(net "M_A_CPU0_SB_DQS_DN<3>")
	)
	(segment
		(start 314.577984 -200.572116)
		(end 314.297568 -200.2917)
		(width 0.20066)
		(layer "F.Cu")
		(net "M_A_CPU0_SB_DQS_DN<3>")
	)
	(segment
		(start 302.421544 -200.137522)
		(end 303.441608 -200.560178)
		(width 0.20066)
		(layer "F.Cu")
		(net "M_A_CPU0_SB_DQS_DN<3>")
	)
	(segment
		(start 331.474572 -219.785946)
		(end 330.839572 -219.150946)
		(width 0.1524)
		(layer "F.Cu")
		(net "M_A_CPU0_SB_DQS_DN<3>")
	)
	(segment
		(start 330.163678 -208.491074)
		(end 329.737974 -208.06537)
		(width 0.20066)
		(layer "F.Cu")
		(net "M_A_CPU0_SB_DQS_DN<3>")
	)
	(segment
		(start 332.081632 -220.310456)
		(end 331.95387 -220.310456)
		(width 0.088646)
		(layer "F.Cu")
		(net "M_A_CPU0_SB_DQS_DN<3>")
	)
	(segment
		(start 301.891954 -199.866758)
		(end 302.162718 -200.137522)
		(width 0.20066)
		(layer "F.Cu")
		(net "M_A_CPU0_SB_DQS_DN<3>")
	)
	(segment
		(start 332.796134 -220.855794)
		(end 332.706472 -220.945456)
		(width 0.088646)
		(layer "F.Cu")
		(net "M_A_CPU0_SB_DQS_DN<3>")
	)
	(segment
		(start 306.644294 -200.285604)
		(end 306.942236 -200.285604)
		(width 0.20066)
		(layer "F.Cu")
		(net "M_A_CPU0_SB_DQS_DN<3>")
	)
	(segment
		(start 329.136502 -207.463898)
		(end 328.710544 -207.03794)
		(width 0.20066)
		(layer "F.Cu")
		(net "M_A_CPU0_SB_DQS_DN<3>")
	)
	(segment
		(start 332.220824 -220.449648)
		(end 332.081632 -220.310456)
		(width 0.088646)
		(layer "F.Cu")
		(net "M_A_CPU0_SB_DQS_DN<3>")
	)
	(segment
		(start 332.372462 -220.728794)
		(end 332.220824 -220.576902)
		(width 0.088646)
		(layer "F.Cu")
		(net "M_A_CPU0_SB_DQS_DN<3>")
	)
	(segment
		(start 331.617066 -210.120484)
		(end 331.191616 -209.695034)
		(width 0.20066)
		(layer "F.Cu")
		(net "M_A_CPU0_SB_DQS_DN<3>")
	)
	(segment
		(start 327.507092 -206.01051)
		(end 327.081642 -205.58506)
		(width 0.20066)
		(layer "F.Cu")
		(net "M_A_CPU0_SB_DQS_DN<3>")
	)
	(segment
		(start 330.765658 -209.093054)
		(end 330.589636 -209.093054)
		(width 0.20066)
		(layer "F.Cu")
		(net "M_A_CPU0_SB_DQS_DN<3>")
	)
	(segment
		(start 331.191616 -209.695034)
		(end 331.191616 -209.519012)
		(width 0.20066)
		(layer "F.Cu")
		(net "M_A_CPU0_SB_DQS_DN<3>")
	)
	(segment
		(start 311.443116 -200.359518)
		(end 311.443116 -200.54443)
		(width 0.20066)
		(layer "F.Cu")
		(net "M_A_CPU0_SB_DQS_DN<3>")
	)
	(segment
		(start 303.670208 -200.560178)
		(end 303.943766 -200.28662)
		(width 0.20066)
		(layer "F.Cu")
		(net "M_A_CPU0_SB_DQS_DN<3>")
	)
	(segment
		(start 331.700124 -214.052658)
		(end 331.700124 -214.033608)
		(width 0.1524)
		(layer "F.Cu")
		(net "M_A_CPU0_SB_DQS_DN<3>")
	)
	(segment
		(start 332.530196 -220.945456)
		(end 332.413864 -220.829124)
		(width 0.088646)
		(layer "F.Cu")
		(net "M_A_CPU0_SB_DQS_DN<3>")
	)
	(segment
		(start 331.490066 -219.846652)
		(end 331.490066 -219.80144)
		(width 0.088646)
		(layer "F.Cu")
		(net "M_A_CPU0_SB_DQS_DN<3>")
	)
	(segment
		(start 330.839572 -219.150946)
		(end 330.839572 -215.52154)
		(width 0.1524)
		(layer "F.Cu")
		(net "M_A_CPU0_SB_DQS_DN<3>")
	)
	(segment
		(start 331.654404 -214.706708)
		(end 331.654404 -214.098378)
		(width 0.1524)
		(layer "F.Cu")
		(net "M_A_CPU0_SB_DQS_DN<3>")
	)
	(segment
		(start 307.216048 -200.559416)
		(end 307.340254 -200.559416)
		(width 0.20066)
		(layer "F.Cu")
		(net "M_A_CPU0_SB_DQS_DN<3>")
	)
	(segment
		(start 311.117742 -200.607676)
		(end 309.934356 -200.117456)
		(width 0.20066)
		(layer "F.Cu")
		(net "M_A_CPU0_SB_DQS_DN<3>")
	)
	(segment
		(start 309.934356 -200.117456)
		(end 309.63108 -200.117456)
		(width 0.20066)
		(layer "F.Cu")
		(net "M_A_CPU0_SB_DQS_DN<3>")
	)
	(segment
		(start 308.057296 -200.107296)
		(end 308.297834 -199.866758)
		(width 0.20066)
		(layer "F.Cu")
		(net "M_A_CPU0_SB_DQS_DN<3>")
	)
	(segment
		(start 332.220824 -220.576902)
		(end 332.220824 -220.449648)
		(width 0.088646)
		(layer "F.Cu")
		(net "M_A_CPU0_SB_DQS_DN<3>")
	)
	(segment
		(start 329.561952 -208.06537)
		(end 329.136502 -207.63992)
		(width 0.20066)
		(layer "F.Cu")
		(net "M_A_CPU0_SB_DQS_DN<3>")
	)
	(segment
		(start 309.379874 -199.866758)
		(end 308.887114 -199.866758)
		(width 0.20066)
		(layer "F.Cu")
		(net "M_A_CPU0_SB_DQS_DN<3>")
	)
	(segment
		(start 326.479662 -204.98308)
		(end 322.068698 -200.572116)
		(width 0.20066)
		(layer "F.Cu")
		(net "M_A_CPU0_SB_DQS_DN<3>")
	)
	(segment
		(start 302.162718 -200.137522)
		(end 302.421544 -200.137522)
		(width 0.20066)
		(layer "F.Cu")
		(net "M_A_CPU0_SB_DQS_DN<3>")
	)
	(segment
		(start 327.081642 -205.58506)
		(end 327.081642 -205.409038)
		(width 0.20066)
		(layer "F.Cu")
		(net "M_A_CPU0_SB_DQS_DN<3>")
	)
	(segment
		(start 311.443116 -200.54443)
		(end 311.37987 -200.607676)
		(width 0.20066)
		(layer "F.Cu")
		(net "M_A_CPU0_SB_DQS_DN<3>")
	)
	(segment
		(start 309.63108 -200.117456)
		(end 309.380128 -199.866504)
		(width 0.20066)
		(layer "F.Cu")
		(net "M_A_CPU0_SB_DQS_DN<3>")
	)
	(segment
		(start 306.638198 -200.2917)
		(end 306.644294 -200.285604)
		(width 0.1016)
		(layer "F.Cu")
		(net "M_A_CPU0_SB_DQS_DN<3>")
	)
	(segment
		(start 331.700124 -214.033608)
		(end 331.700124 -210.321144)
		(width 0.20066)
		(layer "F.Cu")
		(net "M_A_CPU0_SB_DQS_DN<3>")
	)
	(segment
		(start 322.068698 -200.572116)
		(end 314.577984 -200.572116)
		(width 0.20066)
		(layer "F.Cu")
		(net "M_A_CPU0_SB_DQS_DN<3>")
	)
	(segment
		(start 311.929526 -200.274682)
		(end 311.91708 -200.274682)
		(width 0.1016)
		(layer "F.Cu")
		(net "M_A_CPU0_SB_DQS_DN<3>")
	)
	(segment
		(start 301.343314 -199.866758)
		(end 301.891954 -199.866758)
		(width 0.20066)
		(layer "F.Cu")
		(net "M_A_CPU0_SB_DQS_DN<3>")
	)
	(segment
		(start 329.136502 -207.63992)
		(end 329.136502 -207.463898)
		(width 0.20066)
		(layer "F.Cu")
		(net "M_A_CPU0_SB_DQS_DN<3>")
	)
	(segment
		(start 332.706472 -220.945456)
		(end 332.530196 -220.945456)
		(width 0.088646)
		(layer "F.Cu")
		(net "M_A_CPU0_SB_DQS_DN<3>")
	)
	(segment
		(start 327.081642 -205.409038)
		(end 326.655684 -204.98308)
		(width 0.20066)
		(layer "F.Cu")
		(net "M_A_CPU0_SB_DQS_DN<3>")
	)
	(segment
		(start 331.95387 -220.310456)
		(end 331.490066 -219.846652)
		(width 0.088646)
		(layer "F.Cu")
		(net "M_A_CPU0_SB_DQS_DN<3>")
	)
	(segment
		(start 304.319178 -200.28662)
		(end 304.324258 -200.2917)
		(width 0.1016)
		(layer "F.Cu")
		(net "M_A_CPU0_SB_DQS_DN<3>")
	)
	(segment
		(start 306.942236 -200.285604)
		(end 307.216048 -200.559416)
		(width 0.20066)
		(layer "F.Cu")
		(net "M_A_CPU0_SB_DQS_DN<3>")
	)
	(segment
		(start 328.109072 -206.61249)
		(end 328.109072 -206.436468)
		(width 0.20066)
		(layer "F.Cu")
		(net "M_A_CPU0_SB_DQS_DN<3>")
	)
	(segment
		(start 309.380128 -199.866504)
		(end 309.379874 -199.866758)
		(width 0.20066)
		(layer "F.Cu")
		(net "M_A_CPU0_SB_DQS_DN<3>")
	)
	(segment
		(start 311.91708 -200.274682)
		(end 311.527952 -200.274682)
		(width 0.20066)
		(layer "F.Cu")
		(net "M_A_CPU0_SB_DQS_DN<3>")
	)
	(segment
		(start 314.297568 -200.2917)
		(end 314.17768 -200.2917)
		(width 0.20066)
		(layer "F.Cu")
		(net "M_A_CPU0_SB_DQS_DN<3>")
	)
	(segment
		(start 303.943766 -200.28662)
		(end 304.319178 -200.28662)
		(width 0.20066)
		(layer "F.Cu")
		(net "M_A_CPU0_SB_DQS_DN<3>")
	)
	(segment
		(start 327.683114 -206.01051)
		(end 327.507092 -206.01051)
		(width 0.20066)
		(layer "F.Cu")
		(net "M_A_CPU0_SB_DQS_DN<3>")
	)
	(segment
		(start 326.655684 -204.98308)
		(end 326.479662 -204.98308)
		(width 0.20066)
		(layer "F.Cu")
		(net "M_A_CPU0_SB_DQS_DN<3>")
	)
	(segment
		(start 332.413864 -220.829124)
		(end 332.372462 -220.728794)
		(width 0.088646)
		(layer "F.Cu")
		(net "M_A_CPU0_SB_DQS_DN<3>")
	)
	(segment
		(start 314.17768 -200.2917)
		(end 311.946544 -200.2917)
		(width 0.1016)
		(layer "F.Cu")
		(net "M_A_CPU0_SB_DQS_DN<3>")
	)
	(segment
		(start 331.191616 -209.519012)
		(end 330.765658 -209.093054)
		(width 0.20066)
		(layer "F.Cu")
		(net "M_A_CPU0_SB_DQS_DN<3>")
	)
	(segment
		(start 311.527952 -200.274682)
		(end 311.443116 -200.359518)
		(width 0.20066)
		(layer "F.Cu")
		(net "M_A_CPU0_SB_DQS_DN<3>")
	)
	(segment
		(start 308.297834 -199.866758)
		(end 308.887114 -199.866758)
		(width 0.20066)
		(layer "F.Cu")
		(net "M_A_CPU0_SB_DQS_DN<3>")
	)
	(segment
		(start 303.441608 -200.560178)
		(end 303.670208 -200.560178)
		(width 0.20066)
		(layer "F.Cu")
		(net "M_A_CPU0_SB_DQS_DN<3>")
	)
	(segment
		(start 304.324258 -200.2917)
		(end 306.638198 -200.2917)
		(width 0.1016)
		(layer "F.Cu")
		(net "M_A_CPU0_SB_DQS_DN<3>")
	)
	(segment
		(start 307.340254 -200.559416)
		(end 307.792374 -200.107296)
		(width 0.20066)
		(layer "F.Cu")
		(net "M_A_CPU0_SB_DQS_DN<3>")
	)
	(segment
		(start 328.710544 -207.03794)
		(end 328.534522 -207.03794)
		(width 0.20066)
		(layer "F.Cu")
		(net "M_A_CPU0_SB_DQS_DN<3>")
	)
	(segment
		(start 331.700124 -210.321144)
		(end 331.617066 -210.120484)
		(width 0.20066)
		(layer "F.Cu")
		(net "M_A_CPU0_SB_DQS_DN<3>")
	)
	(segment
		(start 330.163678 -208.667096)
		(end 330.163678 -208.491074)
		(width 0.20066)
		(layer "F.Cu")
		(net "M_A_CPU0_SB_DQS_DN<3>")
	)
	(segment
		(start 311.37987 -200.607676)
		(end 311.117742 -200.607676)
		(width 0.20066)
		(layer "F.Cu")
		(net "M_A_CPU0_SB_DQS_DN<3>")
	)
	(segment
		(start 328.534522 -207.03794)
		(end 328.109072 -206.61249)
		(width 0.20066)
		(layer "F.Cu")
		(net "M_A_CPU0_SB_DQS_DN<3>")
	)
	(segment
		(start 331.490066 -219.80144)
		(end 331.474572 -219.785946)
		(width 0.088646)
		(layer "F.Cu")
		(net "M_A_CPU0_SB_DQS_DN<3>")
	)
	(segment
		(start 307.792374 -200.107296)
		(end 308.057296 -200.107296)
		(width 0.20066)
		(layer "F.Cu")
		(net "M_A_CPU0_SB_DQS_DN<3>")
	)
	(segment
		(start 328.109072 -206.436468)
		(end 327.683114 -206.01051)
		(width 0.20066)
		(layer "F.Cu")
		(net "M_A_CPU0_SB_DQS_DN<3>")
	)
	(segment
		(start 330.589636 -209.093054)
		(end 330.163678 -208.667096)
		(width 0.20066)
		(layer "F.Cu")
		(net "M_A_CPU0_SB_DQS_DN<3>")
	)
	(segment
		(start 308.297834 -209.216752)
		(end 308.887114 -209.216752)
		(width 0.20066)
		(layer "F.Cu")
		(net "M_A_CPU0_SB_DQS_DN<2>")
	)
	(segment
		(start 325.181468 -215.779604)
		(end 325.181468 -215.603582)
		(width 0.20066)
		(layer "F.Cu")
		(net "M_A_CPU0_SB_DQS_DN<2>")
	)
	(segment
		(start 310.867044 -209.912204)
		(end 309.856378 -209.493612)
		(width 0.20066)
		(layer "F.Cu")
		(net "M_A_CPU0_SB_DQS_DN<2>")
	)
	(segment
		(start 326.171052 -217.182954)
		(end 325.916036 -216.566496)
		(width 0.1524)
		(layer "F.Cu")
		(net "M_A_CPU0_SB_DQS_DN<2>")
	)
	(segment
		(start 307.340254 -209.90941)
		(end 307.792374 -209.45729)
		(width 0.20066)
		(layer "F.Cu")
		(net "M_A_CPU0_SB_DQS_DN<2>")
	)
	(segment
		(start 325.181468 -215.603582)
		(end 324.75551 -215.177624)
		(width 0.20066)
		(layer "F.Cu")
		(net "M_A_CPU0_SB_DQS_DN<2>")
	)
	(segment
		(start 325.633588 -216.231724)
		(end 325.606664 -216.2048)
		(width 0.1524)
		(layer "F.Cu")
		(net "M_A_CPU0_SB_DQS_DN<2>")
	)
	(segment
		(start 311.207912 -209.912204)
		(end 310.867044 -209.912204)
		(width 0.20066)
		(layer "F.Cu")
		(net "M_A_CPU0_SB_DQS_DN<2>")
	)
	(segment
		(start 324.154038 -214.752174)
		(end 324.154038 -214.576152)
		(width 0.20066)
		(layer "F.Cu")
		(net "M_A_CPU0_SB_DQS_DN<2>")
	)
	(segment
		(start 323.552058 -214.150194)
		(end 323.126608 -213.724744)
		(width 0.20066)
		(layer "F.Cu")
		(net "M_A_CPU0_SB_DQS_DN<2>")
	)
	(segment
		(start 303.951386 -209.628994)
		(end 304.319178 -209.628994)
		(width 0.20066)
		(layer "F.Cu")
		(net "M_A_CPU0_SB_DQS_DN<2>")
	)
	(segment
		(start 309.657242 -209.493612)
		(end 309.380128 -209.216498)
		(width 0.20066)
		(layer "F.Cu")
		(net "M_A_CPU0_SB_DQS_DN<2>")
	)
	(segment
		(start 324.579488 -215.177624)
		(end 324.154038 -214.752174)
		(width 0.20066)
		(layer "F.Cu")
		(net "M_A_CPU0_SB_DQS_DN<2>")
	)
	(segment
		(start 320.044318 -210.466432)
		(end 319.61836 -210.040474)
		(width 0.20066)
		(layer "F.Cu")
		(net "M_A_CPU0_SB_DQS_DN<2>")
	)
	(segment
		(start 325.916036 -216.566496)
		(end 325.633588 -216.284048)
		(width 0.1524)
		(layer "F.Cu")
		(net "M_A_CPU0_SB_DQS_DN<2>")
	)
	(segment
		(start 306.644294 -209.635598)
		(end 306.942236 -209.635598)
		(width 0.20066)
		(layer "F.Cu")
		(net "M_A_CPU0_SB_DQS_DN<2>")
	)
	(segment
		(start 319.289176 -209.887312)
		(end 318.687196 -209.887312)
		(width 0.20066)
		(layer "F.Cu")
		(net "M_A_CPU0_SB_DQS_DN<2>")
	)
	(segment
		(start 323.126608 -213.724744)
		(end 323.126608 -213.548722)
		(width 0.20066)
		(layer "F.Cu")
		(net "M_A_CPU0_SB_DQS_DN<2>")
	)
	(segment
		(start 318.687196 -209.887312)
		(end 318.562736 -209.762852)
		(width 0.20066)
		(layer "F.Cu")
		(net "M_A_CPU0_SB_DQS_DN<2>")
	)
	(segment
		(start 331.89418 -230.672132)
		(end 331.872082 -230.672132)
		(width 0.088646)
		(layer "F.Cu")
		(net "M_A_CPU0_SB_DQS_DN<2>")
	)
	(segment
		(start 318.562736 -209.762852)
		(end 317.960756 -209.762852)
		(width 0.20066)
		(layer "F.Cu")
		(net "M_A_CPU0_SB_DQS_DN<2>")
	)
	(segment
		(start 331.872082 -230.672132)
		(end 331.443076 -230.672132)
		(width 0.1524)
		(layer "F.Cu")
		(net "M_A_CPU0_SB_DQS_DN<2>")
	)
	(segment
		(start 309.379874 -209.216752)
		(end 308.887114 -209.216752)
		(width 0.20066)
		(layer "F.Cu")
		(net "M_A_CPU0_SB_DQS_DN<2>")
	)
	(segment
		(start 320.469768 -211.067904)
		(end 320.044318 -210.642454)
		(width 0.20066)
		(layer "F.Cu")
		(net "M_A_CPU0_SB_DQS_DN<2>")
	)
	(segment
		(start 317.960756 -209.762852)
		(end 317.836296 -209.887312)
		(width 0.20066)
		(layer "F.Cu")
		(net "M_A_CPU0_SB_DQS_DN<2>")
	)
	(segment
		(start 322.70065 -213.122764)
		(end 322.524628 -213.122764)
		(width 0.20066)
		(layer "F.Cu")
		(net "M_A_CPU0_SB_DQS_DN<2>")
	)
	(segment
		(start 324.154038 -214.576152)
		(end 323.72808 -214.150194)
		(width 0.20066)
		(layer "F.Cu")
		(net "M_A_CPU0_SB_DQS_DN<2>")
	)
	(segment
		(start 332.705964 -230.791258)
		(end 332.316836 -230.791258)
		(width 0.088646)
		(layer "F.Cu")
		(net "M_A_CPU0_SB_DQS_DN<2>")
	)
	(segment
		(start 320.64579 -211.067904)
		(end 320.469768 -211.067904)
		(width 0.20066)
		(layer "F.Cu")
		(net "M_A_CPU0_SB_DQS_DN<2>")
	)
	(segment
		(start 321.497198 -212.095334)
		(end 321.071748 -211.669884)
		(width 0.20066)
		(layer "F.Cu")
		(net "M_A_CPU0_SB_DQS_DN<2>")
	)
	(segment
		(start 311.91708 -209.632296)
		(end 311.48782 -209.632296)
		(width 0.20066)
		(layer "F.Cu")
		(net "M_A_CPU0_SB_DQS_DN<2>")
	)
	(segment
		(start 332.229714 -230.704136)
		(end 331.926184 -230.704136)
		(width 0.088646)
		(layer "F.Cu")
		(net "M_A_CPU0_SB_DQS_DN<2>")
	)
	(segment
		(start 302.421544 -209.487516)
		(end 303.441608 -209.910172)
		(width 0.20066)
		(layer "F.Cu")
		(net "M_A_CPU0_SB_DQS_DN<2>")
	)
	(segment
		(start 319.442338 -210.040474)
		(end 319.289176 -209.887312)
		(width 0.20066)
		(layer "F.Cu")
		(net "M_A_CPU0_SB_DQS_DN<2>")
	)
	(segment
		(start 302.162718 -209.487516)
		(end 302.421544 -209.487516)
		(width 0.20066)
		(layer "F.Cu")
		(net "M_A_CPU0_SB_DQS_DN<2>")
	)
	(segment
		(start 314.15228 -209.63382)
		(end 314.144406 -209.63382)
		(width 0.1016)
		(layer "F.Cu")
		(net "M_A_CPU0_SB_DQS_DN<2>")
	)
	(segment
		(start 311.48782 -209.632296)
		(end 311.207912 -209.912204)
		(width 0.20066)
		(layer "F.Cu")
		(net "M_A_CPU0_SB_DQS_DN<2>")
	)
	(segment
		(start 301.343314 -209.216752)
		(end 301.891954 -209.216752)
		(width 0.20066)
		(layer "F.Cu")
		(net "M_A_CPU0_SB_DQS_DN<2>")
	)
	(segment
		(start 325.633588 -216.284048)
		(end 325.633588 -216.231724)
		(width 0.1524)
		(layer "F.Cu")
		(net "M_A_CPU0_SB_DQS_DN<2>")
	)
	(segment
		(start 306.942236 -209.635598)
		(end 307.216048 -209.90941)
		(width 0.20066)
		(layer "F.Cu")
		(net "M_A_CPU0_SB_DQS_DN<2>")
	)
	(segment
		(start 319.61836 -210.040474)
		(end 319.442338 -210.040474)
		(width 0.20066)
		(layer "F.Cu")
		(net "M_A_CPU0_SB_DQS_DN<2>")
	)
	(segment
		(start 325.606664 -216.2048)
		(end 325.181468 -215.779604)
		(width 0.20066)
		(layer "F.Cu")
		(net "M_A_CPU0_SB_DQS_DN<2>")
	)
	(segment
		(start 309.856378 -209.493612)
		(end 309.657242 -209.493612)
		(width 0.20066)
		(layer "F.Cu")
		(net "M_A_CPU0_SB_DQS_DN<2>")
	)
	(segment
		(start 322.099178 -212.521292)
		(end 321.67322 -212.095334)
		(width 0.20066)
		(layer "F.Cu")
		(net "M_A_CPU0_SB_DQS_DN<2>")
	)
	(segment
		(start 322.099178 -212.697314)
		(end 322.099178 -212.521292)
		(width 0.20066)
		(layer "F.Cu")
		(net "M_A_CPU0_SB_DQS_DN<2>")
	)
	(segment
		(start 321.071748 -211.669884)
		(end 321.071748 -211.493862)
		(width 0.20066)
		(layer "F.Cu")
		(net "M_A_CPU0_SB_DQS_DN<2>")
	)
	(segment
		(start 327.776332 -224.865946)
		(end 326.171052 -223.260666)
		(width 0.1524)
		(layer "F.Cu")
		(net "M_A_CPU0_SB_DQS_DN<2>")
	)
	(segment
		(start 326.171052 -223.260666)
		(end 326.171052 -217.182954)
		(width 0.1524)
		(layer "F.Cu")
		(net "M_A_CPU0_SB_DQS_DN<2>")
	)
	(segment
		(start 322.524628 -213.122764)
		(end 322.099178 -212.697314)
		(width 0.20066)
		(layer "F.Cu")
		(net "M_A_CPU0_SB_DQS_DN<2>")
	)
	(segment
		(start 314.78855 -209.887312)
		(end 314.535058 -209.63382)
		(width 0.20066)
		(layer "F.Cu")
		(net "M_A_CPU0_SB_DQS_DN<2>")
	)
	(segment
		(start 324.75551 -215.177624)
		(end 324.579488 -215.177624)
		(width 0.20066)
		(layer "F.Cu")
		(net "M_A_CPU0_SB_DQS_DN<2>")
	)
	(segment
		(start 307.792374 -209.45729)
		(end 308.057296 -209.45729)
		(width 0.20066)
		(layer "F.Cu")
		(net "M_A_CPU0_SB_DQS_DN<2>")
	)
	(segment
		(start 303.441608 -209.910172)
		(end 303.670208 -209.910172)
		(width 0.20066)
		(layer "F.Cu")
		(net "M_A_CPU0_SB_DQS_DN<2>")
	)
	(segment
		(start 331.443076 -230.672132)
		(end 327.776332 -227.005388)
		(width 0.1524)
		(layer "F.Cu")
		(net "M_A_CPU0_SB_DQS_DN<2>")
	)
	(segment
		(start 316.383416 -209.887312)
		(end 314.78855 -209.887312)
		(width 0.20066)
		(layer "F.Cu")
		(net "M_A_CPU0_SB_DQS_DN<2>")
	)
	(segment
		(start 311.926478 -209.641694)
		(end 311.91708 -209.632296)
		(width 0.1016)
		(layer "F.Cu")
		(net "M_A_CPU0_SB_DQS_DN<2>")
	)
	(segment
		(start 332.796134 -230.622602)
		(end 332.796134 -230.701088)
		(width 0.088646)
		(layer "F.Cu")
		(net "M_A_CPU0_SB_DQS_DN<2>")
	)
	(segment
		(start 317.109856 -209.762852)
		(end 316.507876 -209.762852)
		(width 0.20066)
		(layer "F.Cu")
		(net "M_A_CPU0_SB_DQS_DN<2>")
	)
	(segment
		(start 314.136532 -209.641694)
		(end 311.926478 -209.641694)
		(width 0.1016)
		(layer "F.Cu")
		(net "M_A_CPU0_SB_DQS_DN<2>")
	)
	(segment
		(start 301.891954 -209.216752)
		(end 302.162718 -209.487516)
		(width 0.20066)
		(layer "F.Cu")
		(net "M_A_CPU0_SB_DQS_DN<2>")
	)
	(segment
		(start 306.638198 -209.641694)
		(end 306.644294 -209.635598)
		(width 0.1016)
		(layer "F.Cu")
		(net "M_A_CPU0_SB_DQS_DN<2>")
	)
	(segment
		(start 323.72808 -214.150194)
		(end 323.552058 -214.150194)
		(width 0.20066)
		(layer "F.Cu")
		(net "M_A_CPU0_SB_DQS_DN<2>")
	)
	(segment
		(start 323.126608 -213.548722)
		(end 322.70065 -213.122764)
		(width 0.20066)
		(layer "F.Cu")
		(net "M_A_CPU0_SB_DQS_DN<2>")
	)
	(segment
		(start 321.071748 -211.493862)
		(end 320.64579 -211.067904)
		(width 0.20066)
		(layer "F.Cu")
		(net "M_A_CPU0_SB_DQS_DN<2>")
	)
	(segment
		(start 332.316836 -230.791258)
		(end 332.229714 -230.704136)
		(width 0.088646)
		(layer "F.Cu")
		(net "M_A_CPU0_SB_DQS_DN<2>")
	)
	(segment
		(start 308.057296 -209.45729)
		(end 308.297834 -209.216752)
		(width 0.20066)
		(layer "F.Cu")
		(net "M_A_CPU0_SB_DQS_DN<2>")
	)
	(segment
		(start 320.044318 -210.642454)
		(end 320.044318 -210.466432)
		(width 0.20066)
		(layer "F.Cu")
		(net "M_A_CPU0_SB_DQS_DN<2>")
	)
	(segment
		(start 316.507876 -209.762852)
		(end 316.383416 -209.887312)
		(width 0.20066)
		(layer "F.Cu")
		(net "M_A_CPU0_SB_DQS_DN<2>")
	)
	(segment
		(start 321.67322 -212.095334)
		(end 321.497198 -212.095334)
		(width 0.20066)
		(layer "F.Cu")
		(net "M_A_CPU0_SB_DQS_DN<2>")
	)
	(segment
		(start 332.796134 -230.701088)
		(end 332.705964 -230.791258)
		(width 0.088646)
		(layer "F.Cu")
		(net "M_A_CPU0_SB_DQS_DN<2>")
	)
	(segment
		(start 304.331878 -209.641694)
		(end 306.638198 -209.641694)
		(width 0.1016)
		(layer "F.Cu")
		(net "M_A_CPU0_SB_DQS_DN<2>")
	)
	(segment
		(start 303.670208 -209.910172)
		(end 303.951386 -209.628994)
		(width 0.20066)
		(layer "F.Cu")
		(net "M_A_CPU0_SB_DQS_DN<2>")
	)
	(segment
		(start 331.926184 -230.704136)
		(end 331.89418 -230.672132)
		(width 0.088646)
		(layer "F.Cu")
		(net "M_A_CPU0_SB_DQS_DN<2>")
	)
	(segment
		(start 314.144406 -209.63382)
		(end 314.136532 -209.641694)
		(width 0.1016)
		(layer "F.Cu")
		(net "M_A_CPU0_SB_DQS_DN<2>")
	)
	(segment
		(start 317.836296 -209.887312)
		(end 317.234316 -209.887312)
		(width 0.20066)
		(layer "F.Cu")
		(net "M_A_CPU0_SB_DQS_DN<2>")
	)
	(segment
		(start 317.234316 -209.887312)
		(end 317.109856 -209.762852)
		(width 0.20066)
		(layer "F.Cu")
		(net "M_A_CPU0_SB_DQS_DN<2>")
	)
	(segment
		(start 307.216048 -209.90941)
		(end 307.340254 -209.90941)
		(width 0.20066)
		(layer "F.Cu")
		(net "M_A_CPU0_SB_DQS_DN<2>")
	)
	(segment
		(start 314.535058 -209.63382)
		(end 314.15228 -209.63382)
		(width 0.20066)
		(layer "F.Cu")
		(net "M_A_CPU0_SB_DQS_DN<2>")
	)
	(segment
		(start 309.380128 -209.216498)
		(end 309.379874 -209.216752)
		(width 0.20066)
		(layer "F.Cu")
		(net "M_A_CPU0_SB_DQS_DN<2>")
	)
	(segment
		(start 304.319178 -209.628994)
		(end 304.331878 -209.641694)
		(width 0.1016)
		(layer "F.Cu")
		(net "M_A_CPU0_SB_DQS_DN<2>")
	)
	(segment
		(start 327.776332 -227.005388)
		(end 327.776332 -224.865946)
		(width 0.1524)
		(layer "F.Cu")
		(net "M_A_CPU0_SB_DQS_DN<2>")
	)
	(segment
		(start 316.931802 -220.770958)
		(end 316.505844 -220.345)
		(width 0.20066)
		(layer "F.Cu")
		(net "M_A_CPU0_SB_DQS_DN<1>")
	)
	(segment
		(start 332.796134 -235.571538)
		(end 332.689962 -235.67771)
		(width 0.088646)
		(layer "F.Cu")
		(net "M_A_CPU0_SB_DQS_DN<1>")
	)
	(segment
		(start 304.319178 -218.986608)
		(end 304.324258 -218.991688)
		(width 0.101854)
		(layer "F.Cu")
		(net "M_A_CPU0_SB_DQS_DN<1>")
	)
	(segment
		(start 303.441608 -219.260166)
		(end 303.670208 -219.260166)
		(width 0.20066)
		(layer "F.Cu")
		(net "M_A_CPU0_SB_DQS_DN<1>")
	)
	(segment
		(start 314.039504 -218.991688)
		(end 311.847484 -218.991688)
		(width 0.1016)
		(layer "F.Cu")
		(net "M_A_CPU0_SB_DQS_DN<1>")
	)
	(segment
		(start 303.670208 -219.260166)
		(end 303.944274 -218.9861)
		(width 0.20066)
		(layer "F.Cu")
		(net "M_A_CPU0_SB_DQS_DN<1>")
	)
	(segment
		(start 316.505844 -220.345)
		(end 316.329822 -220.345)
		(width 0.20066)
		(layer "F.Cu")
		(net "M_A_CPU0_SB_DQS_DN<1>")
	)
	(segment
		(start 302.421544 -218.83751)
		(end 303.441608 -219.260166)
		(width 0.20066)
		(layer "F.Cu")
		(net "M_A_CPU0_SB_DQS_DN<1>")
	)
	(segment
		(start 322.84289 -229.59314)
		(end 322.71843 -229.7176)
		(width 0.20066)
		(layer "F.Cu")
		(net "M_A_CPU0_SB_DQS_DN<1>")
	)
	(segment
		(start 322.71843 -229.7176)
		(end 322.11645 -229.7176)
		(width 0.20066)
		(layer "F.Cu")
		(net "M_A_CPU0_SB_DQS_DN<1>")
	)
	(segment
		(start 306.638198 -218.991688)
		(end 306.644294 -218.985592)
		(width 0.101854)
		(layer "F.Cu")
		(net "M_A_CPU0_SB_DQS_DN<1>")
	)
	(segment
		(start 319.760346 -228.69017)
		(end 319.584324 -228.69017)
		(width 0.20066)
		(layer "F.Cu")
		(net "M_A_CPU0_SB_DQS_DN<1>")
	)
	(segment
		(start 303.944274 -218.9861)
		(end 304.31867 -218.9861)
		(width 0.20066)
		(layer "F.Cu")
		(net "M_A_CPU0_SB_DQS_DN<1>")
	)
	(segment
		(start 301.343314 -218.566746)
		(end 301.891954 -218.566746)
		(width 0.20066)
		(layer "F.Cu")
		(net "M_A_CPU0_SB_DQS_DN<1>")
	)
	(segment
		(start 317.959232 -221.97441)
		(end 317.959232 -221.798388)
		(width 0.20066)
		(layer "F.Cu")
		(net "M_A_CPU0_SB_DQS_DN<1>")
	)
	(segment
		(start 331.951584 -235.492798)
		(end 331.464412 -235.492798)
		(width 0.088646)
		(layer "F.Cu")
		(net "M_A_CPU0_SB_DQS_DN<1>")
	)
	(segment
		(start 318.509142 -226.162108)
		(end 318.384682 -226.037648)
		(width 0.20066)
		(layer "F.Cu")
		(net "M_A_CPU0_SB_DQS_DN<1>")
	)
	(segment
		(start 314.499498 -218.983052)
		(end 314.17768 -218.983052)
		(width 0.20066)
		(layer "F.Cu")
		(net "M_A_CPU0_SB_DQS_DN<1>")
	)
	(segment
		(start 306.644294 -218.985592)
		(end 306.942236 -218.985592)
		(width 0.20066)
		(layer "F.Cu")
		(net "M_A_CPU0_SB_DQS_DN<1>")
	)
	(segment
		(start 318.556894 -227.66274)
		(end 318.384682 -227.490528)
		(width 0.20066)
		(layer "F.Cu")
		(net "M_A_CPU0_SB_DQS_DN<1>")
	)
	(segment
		(start 306.942236 -218.985592)
		(end 307.216048 -219.259404)
		(width 0.20066)
		(layer "F.Cu")
		(net "M_A_CPU0_SB_DQS_DN<1>")
	)
	(segment
		(start 307.216048 -219.259404)
		(end 307.340254 -219.259404)
		(width 0.20066)
		(layer "F.Cu")
		(net "M_A_CPU0_SB_DQS_DN<1>")
	)
	(segment
		(start 320.611754 -229.7176)
		(end 320.186304 -229.29215)
		(width 0.20066)
		(layer "F.Cu")
		(net "M_A_CPU0_SB_DQS_DN<1>")
	)
	(segment
		(start 318.509142 -225.311208)
		(end 318.509142 -224.709228)
		(width 0.20066)
		(layer "F.Cu")
		(net "M_A_CPU0_SB_DQS_DN<1>")
	)
	(segment
		(start 330.63942 -235.461048)
		(end 325.100442 -229.92207)
		(width 0.1524)
		(layer "F.Cu")
		(net "M_A_CPU0_SB_DQS_DN<1>")
	)
	(segment
		(start 304.31867 -218.9861)
		(end 304.319178 -218.986608)
		(width 0.20066)
		(layer "F.Cu")
		(net "M_A_CPU0_SB_DQS_DN<1>")
	)
	(segment
		(start 324.20941 -229.7176)
		(end 324.17131 -229.7176)
		(width 0.1524)
		(layer "F.Cu")
		(net "M_A_CPU0_SB_DQS_DN<1>")
	)
	(segment
		(start 320.186304 -229.116128)
		(end 319.760346 -228.69017)
		(width 0.20066)
		(layer "F.Cu")
		(net "M_A_CPU0_SB_DQS_DN<1>")
	)
	(segment
		(start 323.56933 -229.7176)
		(end 323.44487 -229.59314)
		(width 0.20066)
		(layer "F.Cu")
		(net "M_A_CPU0_SB_DQS_DN<1>")
	)
	(segment
		(start 308.057296 -218.807284)
		(end 308.297834 -218.566746)
		(width 0.20066)
		(layer "F.Cu")
		(net "M_A_CPU0_SB_DQS_DN<1>")
	)
	(segment
		(start 306.321206 -218.991688)
		(end 306.638198 -218.991688)
		(width 0.101854)
		(layer "F.Cu")
		(net "M_A_CPU0_SB_DQS_DN<1>")
	)
	(segment
		(start 316.329822 -220.345)
		(end 315.237876 -219.253054)
		(width 0.20066)
		(layer "F.Cu")
		(net "M_A_CPU0_SB_DQS_DN<1>")
	)
	(segment
		(start 314.7695 -219.253054)
		(end 314.499498 -218.983052)
		(width 0.20066)
		(layer "F.Cu")
		(net "M_A_CPU0_SB_DQS_DN<1>")
	)
	(segment
		(start 318.509142 -223.256348)
		(end 318.384682 -223.131888)
		(width 0.20066)
		(layer "F.Cu")
		(net "M_A_CPU0_SB_DQS_DN<1>")
	)
	(segment
		(start 302.162718 -218.83751)
		(end 302.421544 -218.83751)
		(width 0.20066)
		(layer "F.Cu")
		(net "M_A_CPU0_SB_DQS_DN<1>")
	)
	(segment
		(start 324.348348 -229.752906)
		(end 324.246494 -229.754176)
		(width 0.1524)
		(layer "F.Cu")
		(net "M_A_CPU0_SB_DQS_DN<1>")
	)
	(segment
		(start 319.584324 -228.69017)
		(end 319.158874 -228.26472)
		(width 0.20066)
		(layer "F.Cu")
		(net "M_A_CPU0_SB_DQS_DN<1>")
	)
	(segment
		(start 324.17131 -229.7176)
		(end 323.56933 -229.7176)
		(width 0.20066)
		(layer "F.Cu")
		(net "M_A_CPU0_SB_DQS_DN<1>")
	)
	(segment
		(start 318.384682 -222.39986)
		(end 317.959232 -221.97441)
		(width 0.20066)
		(layer "F.Cu")
		(net "M_A_CPU0_SB_DQS_DN<1>")
	)
	(segment
		(start 311.182512 -219.262706)
		(end 310.929782 -219.262706)
		(width 0.20066)
		(layer "F.Cu")
		(net "M_A_CPU0_SB_DQS_DN<1>")
	)
	(segment
		(start 315.237876 -219.253054)
		(end 314.7695 -219.253054)
		(width 0.20066)
		(layer "F.Cu")
		(net "M_A_CPU0_SB_DQS_DN<1>")
	)
	(segment
		(start 307.792374 -218.807284)
		(end 308.057296 -218.807284)
		(width 0.20066)
		(layer "F.Cu")
		(net "M_A_CPU0_SB_DQS_DN<1>")
	)
	(segment
		(start 318.384682 -226.037648)
		(end 318.384682 -225.435668)
		(width 0.20066)
		(layer "F.Cu")
		(net "M_A_CPU0_SB_DQS_DN<1>")
	)
	(segment
		(start 321.39001 -229.59314)
		(end 321.26555 -229.7176)
		(width 0.20066)
		(layer "F.Cu")
		(net "M_A_CPU0_SB_DQS_DN<1>")
	)
	(segment
		(start 309.379874 -218.566746)
		(end 308.887114 -218.566746)
		(width 0.20066)
		(layer "F.Cu")
		(net "M_A_CPU0_SB_DQS_DN<1>")
	)
	(segment
		(start 318.732916 -227.66274)
		(end 318.556894 -227.66274)
		(width 0.20066)
		(layer "F.Cu")
		(net "M_A_CPU0_SB_DQS_DN<1>")
	)
	(segment
		(start 321.99199 -229.59314)
		(end 321.39001 -229.59314)
		(width 0.20066)
		(layer "F.Cu")
		(net "M_A_CPU0_SB_DQS_DN<1>")
	)
	(segment
		(start 332.689962 -235.67771)
		(end 332.136496 -235.67771)
		(width 0.088646)
		(layer "F.Cu")
		(net "M_A_CPU0_SB_DQS_DN<1>")
	)
	(segment
		(start 318.509142 -226.764088)
		(end 318.509142 -226.162108)
		(width 0.20066)
		(layer "F.Cu")
		(net "M_A_CPU0_SB_DQS_DN<1>")
	)
	(segment
		(start 318.384682 -226.888548)
		(end 318.509142 -226.764088)
		(width 0.20066)
		(layer "F.Cu")
		(net "M_A_CPU0_SB_DQS_DN<1>")
	)
	(segment
		(start 324.69201 -229.752906)
		(end 324.348348 -229.752906)
		(width 0.1524)
		(layer "F.Cu")
		(net "M_A_CPU0_SB_DQS_DN<1>")
	)
	(segment
		(start 320.186304 -229.29215)
		(end 320.186304 -229.116128)
		(width 0.20066)
		(layer "F.Cu")
		(net "M_A_CPU0_SB_DQS_DN<1>")
	)
	(segment
		(start 322.11645 -229.7176)
		(end 321.99199 -229.59314)
		(width 0.20066)
		(layer "F.Cu")
		(net "M_A_CPU0_SB_DQS_DN<1>")
	)
	(segment
		(start 332.796134 -235.506006)
		(end 332.796134 -235.571538)
		(width 0.088646)
		(layer "F.Cu")
		(net "M_A_CPU0_SB_DQS_DN<1>")
	)
	(segment
		(start 318.384682 -227.490528)
		(end 318.384682 -226.888548)
		(width 0.20066)
		(layer "F.Cu")
		(net "M_A_CPU0_SB_DQS_DN<1>")
	)
	(segment
		(start 318.384682 -224.584768)
		(end 318.384682 -223.982788)
		(width 0.20066)
		(layer "F.Cu")
		(net "M_A_CPU0_SB_DQS_DN<1>")
	)
	(segment
		(start 304.324258 -218.991688)
		(end 306.321206 -218.991688)
		(width 0.1016)
		(layer "F.Cu")
		(net "M_A_CPU0_SB_DQS_DN<1>")
	)
	(segment
		(start 332.136496 -235.67771)
		(end 331.951584 -235.492798)
		(width 0.088646)
		(layer "F.Cu")
		(net "M_A_CPU0_SB_DQS_DN<1>")
	)
	(segment
		(start 311.847484 -218.991688)
		(end 311.84088 -218.985084)
		(width 0.1016)
		(layer "F.Cu")
		(net "M_A_CPU0_SB_DQS_DN<1>")
	)
	(segment
		(start 310.929782 -219.262706)
		(end 309.903876 -218.837764)
		(width 0.20066)
		(layer "F.Cu")
		(net "M_A_CPU0_SB_DQS_DN<1>")
	)
	(segment
		(start 321.26555 -229.7176)
		(end 320.611754 -229.7176)
		(width 0.20066)
		(layer "F.Cu")
		(net "M_A_CPU0_SB_DQS_DN<1>")
	)
	(segment
		(start 314.04814 -218.983052)
		(end 314.039504 -218.991688)
		(width 0.1016)
		(layer "F.Cu")
		(net "M_A_CPU0_SB_DQS_DN<1>")
	)
	(segment
		(start 309.903876 -218.837764)
		(end 309.6514 -218.837764)
		(width 0.20066)
		(layer "F.Cu")
		(net "M_A_CPU0_SB_DQS_DN<1>")
	)
	(segment
		(start 318.384682 -223.131888)
		(end 318.384682 -222.39986)
		(width 0.20066)
		(layer "F.Cu")
		(net "M_A_CPU0_SB_DQS_DN<1>")
	)
	(segment
		(start 318.509142 -224.709228)
		(end 318.384682 -224.584768)
		(width 0.20066)
		(layer "F.Cu")
		(net "M_A_CPU0_SB_DQS_DN<1>")
	)
	(segment
		(start 317.959232 -221.798388)
		(end 317.533274 -221.37243)
		(width 0.20066)
		(layer "F.Cu")
		(net "M_A_CPU0_SB_DQS_DN<1>")
	)
	(segment
		(start 318.384682 -225.435668)
		(end 318.509142 -225.311208)
		(width 0.20066)
		(layer "F.Cu")
		(net "M_A_CPU0_SB_DQS_DN<1>")
	)
	(segment
		(start 314.17768 -218.983052)
		(end 314.04814 -218.983052)
		(width 0.1016)
		(layer "F.Cu")
		(net "M_A_CPU0_SB_DQS_DN<1>")
	)
	(segment
		(start 331.432662 -235.461048)
		(end 331.410564 -235.461048)
		(width 0.088646)
		(layer "F.Cu")
		(net "M_A_CPU0_SB_DQS_DN<1>")
	)
	(segment
		(start 319.158874 -228.088698)
		(end 318.732916 -227.66274)
		(width 0.20066)
		(layer "F.Cu")
		(net "M_A_CPU0_SB_DQS_DN<1>")
	)
	(segment
		(start 316.931802 -220.94698)
		(end 316.931802 -220.770958)
		(width 0.20066)
		(layer "F.Cu")
		(net "M_A_CPU0_SB_DQS_DN<1>")
	)
	(segment
		(start 308.297834 -218.566746)
		(end 308.887114 -218.566746)
		(width 0.20066)
		(layer "F.Cu")
		(net "M_A_CPU0_SB_DQS_DN<1>")
	)
	(segment
		(start 325.100442 -229.92207)
		(end 324.69201 -229.752906)
		(width 0.1524)
		(layer "F.Cu")
		(net "M_A_CPU0_SB_DQS_DN<1>")
	)
	(segment
		(start 311.84088 -218.985084)
		(end 311.460134 -218.985084)
		(width 0.20066)
		(layer "F.Cu")
		(net "M_A_CPU0_SB_DQS_DN<1>")
	)
	(segment
		(start 319.158874 -228.26472)
		(end 319.158874 -228.088698)
		(width 0.20066)
		(layer "F.Cu")
		(net "M_A_CPU0_SB_DQS_DN<1>")
	)
	(segment
		(start 318.384682 -223.982788)
		(end 318.509142 -223.858328)
		(width 0.20066)
		(layer "F.Cu")
		(net "M_A_CPU0_SB_DQS_DN<1>")
	)
	(segment
		(start 307.340254 -219.259404)
		(end 307.792374 -218.807284)
		(width 0.20066)
		(layer "F.Cu")
		(net "M_A_CPU0_SB_DQS_DN<1>")
	)
	(segment
		(start 331.464412 -235.492798)
		(end 331.432662 -235.461048)
		(width 0.088646)
		(layer "F.Cu")
		(net "M_A_CPU0_SB_DQS_DN<1>")
	)
	(segment
		(start 317.357252 -221.37243)
		(end 316.931802 -220.94698)
		(width 0.20066)
		(layer "F.Cu")
		(net "M_A_CPU0_SB_DQS_DN<1>")
	)
	(segment
		(start 309.6514 -218.837764)
		(end 309.380128 -218.566492)
		(width 0.20066)
		(layer "F.Cu")
		(net "M_A_CPU0_SB_DQS_DN<1>")
	)
	(segment
		(start 331.410564 -235.461048)
		(end 330.63942 -235.461048)
		(width 0.1524)
		(layer "F.Cu")
		(net "M_A_CPU0_SB_DQS_DN<1>")
	)
	(segment
		(start 301.891954 -218.566746)
		(end 302.162718 -218.83751)
		(width 0.20066)
		(layer "F.Cu")
		(net "M_A_CPU0_SB_DQS_DN<1>")
	)
	(segment
		(start 317.533274 -221.37243)
		(end 317.357252 -221.37243)
		(width 0.20066)
		(layer "F.Cu")
		(net "M_A_CPU0_SB_DQS_DN<1>")
	)
	(segment
		(start 311.460134 -218.985084)
		(end 311.182512 -219.262706)
		(width 0.20066)
		(layer "F.Cu")
		(net "M_A_CPU0_SB_DQS_DN<1>")
	)
	(segment
		(start 309.380128 -218.566492)
		(end 309.379874 -218.566746)
		(width 0.20066)
		(layer "F.Cu")
		(net "M_A_CPU0_SB_DQS_DN<1>")
	)
	(segment
		(start 323.44487 -229.59314)
		(end 322.84289 -229.59314)
		(width 0.20066)
		(layer "F.Cu")
		(net "M_A_CPU0_SB_DQS_DN<1>")
	)
	(segment
		(start 324.246494 -229.754176)
		(end 324.20941 -229.7176)
		(width 0.1524)
		(layer "F.Cu")
		(net "M_A_CPU0_SB_DQS_DN<1>")
	)
	(segment
		(start 318.509142 -223.858328)
		(end 318.509142 -223.256348)
		(width 0.20066)
		(layer "F.Cu")
		(net "M_A_CPU0_SB_DQS_DN<1>")
	)
	(segment
		(start 306.644294 -228.341682)
		(end 306.321206 -228.341682)
		(width 0.101854)
		(layer "F.Cu")
		(net "M_A_CPU0_SB_DQS_DN<0>")
	)
	(segment
		(start 336.085434 -237.947454)
		(end 336.085434 -237.411514)
		(width 0.20066)
		(layer "F.Cu")
		(net "M_A_CPU0_SB_DQS_DN<0>")
	)
	(segment
		(start 308.297834 -227.91674)
		(end 308.057296 -228.157278)
		(width 0.20066)
		(layer "F.Cu")
		(net "M_A_CPU0_SB_DQS_DN<0>")
	)
	(segment
		(start 301.891954 -227.91674)
		(end 301.343314 -227.91674)
		(width 0.20066)
		(layer "F.Cu")
		(net "M_A_CPU0_SB_DQS_DN<0>")
	)
	(segment
		(start 306.783486 -228.341682)
		(end 306.644294 -228.341682)
		(width 0.20066)
		(layer "F.Cu")
		(net "M_A_CPU0_SB_DQS_DN<0>")
	)
	(segment
		(start 304.124614 -228.336602)
		(end 303.842166 -228.61905)
		(width 0.20066)
		(layer "F.Cu")
		(net "M_A_CPU0_SB_DQS_DN<0>")
	)
	(segment
		(start 308.887114 -227.91674)
		(end 308.297834 -227.91674)
		(width 0.20066)
		(layer "F.Cu")
		(net "M_A_CPU0_SB_DQS_DN<0>")
	)
	(segment
		(start 303.842166 -228.61905)
		(end 303.580546 -228.61905)
		(width 0.20066)
		(layer "F.Cu")
		(net "M_A_CPU0_SB_DQS_DN<0>")
	)
	(segment
		(start 307.693314 -228.157278)
		(end 307.241194 -228.609398)
		(width 0.20066)
		(layer "F.Cu")
		(net "M_A_CPU0_SB_DQS_DN<0>")
	)
	(segment
		(start 308.057296 -228.157278)
		(end 307.693314 -228.157278)
		(width 0.20066)
		(layer "F.Cu")
		(net "M_A_CPU0_SB_DQS_DN<0>")
	)
	(segment
		(start 304.319178 -228.336602)
		(end 304.124614 -228.336602)
		(width 0.20066)
		(layer "F.Cu")
		(net "M_A_CPU0_SB_DQS_DN<0>")
	)
	(segment
		(start 307.051202 -228.609398)
		(end 306.783486 -228.341682)
		(width 0.20066)
		(layer "F.Cu")
		(net "M_A_CPU0_SB_DQS_DN<0>")
	)
	(segment
		(start 304.331878 -228.336602)
		(end 304.319178 -228.336602)
		(width 0.101854)
		(layer "F.Cu")
		(net "M_A_CPU0_SB_DQS_DN<0>")
	)
	(segment
		(start 307.241194 -228.609398)
		(end 307.051202 -228.609398)
		(width 0.20066)
		(layer "F.Cu")
		(net "M_A_CPU0_SB_DQS_DN<0>")
	)
	(segment
		(start 304.336958 -228.341682)
		(end 304.331878 -228.336602)
		(width 0.101854)
		(layer "F.Cu")
		(net "M_A_CPU0_SB_DQS_DN<0>")
	)
	(segment
		(start 302.538892 -228.187504)
		(end 302.162718 -228.187504)
		(width 0.20066)
		(layer "F.Cu")
		(net "M_A_CPU0_SB_DQS_DN<0>")
	)
	(segment
		(start 303.580546 -228.61905)
		(end 302.538892 -228.187504)
		(width 0.20066)
		(layer "F.Cu")
		(net "M_A_CPU0_SB_DQS_DN<0>")
	)
	(segment
		(start 306.321206 -228.341682)
		(end 304.336958 -228.341682)
		(width 0.1016)
		(layer "F.Cu")
		(net "M_A_CPU0_SB_DQS_DN<0>")
	)
	(segment
		(start 309.992014 -227.91674)
		(end 308.887114 -227.91674)
		(width 0.20066)
		(layer "F.Cu")
		(net "M_A_CPU0_SB_DQS_DN<0>")
	)
	(segment
		(start 302.162718 -228.187504)
		(end 301.891954 -227.91674)
		(width 0.20066)
		(layer "F.Cu")
		(net "M_A_CPU0_SB_DQS_DN<0>")
	)
	(segment
		(start 319.53073 -229.382066)
		(end 319.142618 -228.993954)
		(width 0.18288)
		(layer "In2.Cu")
		(net "M_A_CPU0_SB_DQS_DN<0>")
	)
	(segment
		(start 334.018636 -237.736126)
		(end 334.008222 -237.73003)
		(width 0.088646)
		(layer "In2.Cu")
		(net "M_A_CPU0_SB_DQS_DN<0>")
	)
	(segment
		(start 330.759308 -237.643924)
		(end 330.699364 -237.58398)
		(width 0.088646)
		(layer "In2.Cu")
		(net "M_A_CPU0_SB_DQS_DN<0>")
	)
	(segment
		(start 314.288932 -228.341682)
		(end 314.185046 -228.341682)
		(width 0.18288)
		(layer "In2.Cu")
		(net "M_A_CPU0_SB_DQS_DN<0>")
	)
	(segment
		(start 324.29069 -234.142026)
		(end 323.902578 -233.753914)
		(width 0.18288)
		(layer "In2.Cu")
		(net "M_A_CPU0_SB_DQS_DN<0>")
	)
	(segment
		(start 322.386706 -232.238042)
		(end 321.998594 -231.84993)
		(width 0.18288)
		(layer "In2.Cu")
		(net "M_A_CPU0_SB_DQS_DN<0>")
	)
	(segment
		(start 313.899296 -228.341682)
		(end 313.65444 -228.586538)
		(width 0.18288)
		(layer "In2.Cu")
		(net "M_A_CPU0_SB_DQS_DN<0>")
	)
	(segment
		(start 312.341514 -228.416612)
		(end 312.14187 -228.216968)
		(width 0.16002)
		(layer "In2.Cu")
		(net "M_A_CPU0_SB_DQS_DN<0>")
	)
	(segment
		(start 335.901538 -237.59541)
		(end 335.857342 -237.59541)
		(width 0.088646)
		(layer "In2.Cu")
		(net "M_A_CPU0_SB_DQS_DN<0>")
	)
	(segment
		(start 314.014866 -228.341682)
		(end 313.899296 -228.341682)
		(width 0.18288)
		(layer "In2.Cu")
		(net "M_A_CPU0_SB_DQS_DN<0>")
	)
	(segment
		(start 317.111634 -228.606096)
		(end 316.562994 -228.606096)
		(width 0.18288)
		(layer "In2.Cu")
		(net "M_A_CPU0_SB_DQS_DN<0>")
	)
	(segment
		(start 316.438534 -228.481636)
		(end 315.889894 -228.481636)
		(width 0.18288)
		(layer "In2.Cu")
		(net "M_A_CPU0_SB_DQS_DN<0>")
	)
	(segment
		(start 321.822572 -231.84993)
		(end 321.434714 -231.462072)
		(width 0.18288)
		(layer "In2.Cu")
		(net "M_A_CPU0_SB_DQS_DN<0>")
	)
	(segment
		(start 334.958182 -237.736126)
		(end 334.947768 -237.73003)
		(width 0.088646)
		(layer "In2.Cu")
		(net "M_A_CPU0_SB_DQS_DN<0>")
	)
	(segment
		(start 321.434714 -231.462072)
		(end 321.434714 -231.28605)
		(width 0.18288)
		(layer "In2.Cu")
		(net "M_A_CPU0_SB_DQS_DN<0>")
	)
	(segment
		(start 312.35777 -228.416612)
		(end 312.341514 -228.416612)
		(width 0.16002)
		(layer "In2.Cu")
		(net "M_A_CPU0_SB_DQS_DN<0>")
	)
	(segment
		(start 331.79385 -237.643924)
		(end 330.759308 -237.643924)
		(width 0.088646)
		(layer "In2.Cu")
		(net "M_A_CPU0_SB_DQS_DN<0>")
	)
	(segment
		(start 330.699364 -237.58398)
		(end 327.556622 -237.58398)
		(width 0.18288)
		(layer "In2.Cu")
		(net "M_A_CPU0_SB_DQS_DN<0>")
	)
	(segment
		(start 311.227978 -227.931218)
		(end 310.610758 -228.186742)
		(width 0.18288)
		(layer "In2.Cu")
		(net "M_A_CPU0_SB_DQS_DN<0>")
	)
	(segment
		(start 317.784734 -228.481636)
		(end 317.236094 -228.481636)
		(width 0.18288)
		(layer "In2.Cu")
		(net "M_A_CPU0_SB_DQS_DN<0>")
	)
	(segment
		(start 313.65444 -228.586538)
		(end 312.527696 -228.586538)
		(width 0.18288)
		(layer "In2.Cu")
		(net "M_A_CPU0_SB_DQS_DN<0>")
	)
	(segment
		(start 312.14187 -228.200712)
		(end 312.113676 -228.172518)
		(width 0.16002)
		(layer "In2.Cu")
		(net "M_A_CPU0_SB_DQS_DN<0>")
	)
	(segment
		(start 325.242682 -235.27004)
		(end 325.242682 -235.094018)
		(width 0.18288)
		(layer "In2.Cu")
		(net "M_A_CPU0_SB_DQS_DN<0>")
	)
	(segment
		(start 323.726556 -233.753914)
		(end 323.338698 -233.366056)
		(width 0.18288)
		(layer "In2.Cu")
		(net "M_A_CPU0_SB_DQS_DN<0>")
	)
	(segment
		(start 315.889894 -228.481636)
		(end 315.765434 -228.606096)
		(width 0.18288)
		(layer "In2.Cu")
		(net "M_A_CPU0_SB_DQS_DN<0>")
	)
	(segment
		(start 323.902578 -233.753914)
		(end 323.726556 -233.753914)
		(width 0.18288)
		(layer "In2.Cu")
		(net "M_A_CPU0_SB_DQS_DN<0>")
	)
	(segment
		(start 324.678548 -234.705906)
		(end 324.29069 -234.318048)
		(width 0.18288)
		(layer "In2.Cu")
		(net "M_A_CPU0_SB_DQS_DN<0>")
	)
	(segment
		(start 321.046602 -230.897938)
		(end 320.87058 -230.897938)
		(width 0.18288)
		(layer "In2.Cu")
		(net "M_A_CPU0_SB_DQS_DN<0>")
	)
	(segment
		(start 310.610758 -228.186742)
		(end 310.262016 -228.186742)
		(width 0.18288)
		(layer "In2.Cu")
		(net "M_A_CPU0_SB_DQS_DN<0>")
	)
	(segment
		(start 319.53073 -229.558088)
		(end 319.53073 -229.382066)
		(width 0.18288)
		(layer "In2.Cu")
		(net "M_A_CPU0_SB_DQS_DN<0>")
	)
	(segment
		(start 312.113676 -228.172518)
		(end 311.872376 -227.931218)
		(width 0.18288)
		(layer "In2.Cu")
		(net "M_A_CPU0_SB_DQS_DN<0>")
	)
	(segment
		(start 324.29069 -234.318048)
		(end 324.29069 -234.142026)
		(width 0.18288)
		(layer "In2.Cu")
		(net "M_A_CPU0_SB_DQS_DN<0>")
	)
	(segment
		(start 327.556622 -237.58398)
		(end 325.242682 -235.27004)
		(width 0.18288)
		(layer "In2.Cu")
		(net "M_A_CPU0_SB_DQS_DN<0>")
	)
	(segment
		(start 322.774564 -232.801922)
		(end 322.386706 -232.414064)
		(width 0.18288)
		(layer "In2.Cu")
		(net "M_A_CPU0_SB_DQS_DN<0>")
	)
	(segment
		(start 312.385964 -228.444806)
		(end 312.35777 -228.416612)
		(width 0.16002)
		(layer "In2.Cu")
		(net "M_A_CPU0_SB_DQS_DN<0>")
	)
	(segment
		(start 317.236094 -228.481636)
		(end 317.111634 -228.606096)
		(width 0.18288)
		(layer "In2.Cu")
		(net "M_A_CPU0_SB_DQS_DN<0>")
	)
	(segment
		(start 316.562994 -228.606096)
		(end 316.438534 -228.481636)
		(width 0.18288)
		(layer "In2.Cu")
		(net "M_A_CPU0_SB_DQS_DN<0>")
	)
	(segment
		(start 323.338698 -233.366056)
		(end 323.338698 -233.190034)
		(width 0.18288)
		(layer "In2.Cu")
		(net "M_A_CPU0_SB_DQS_DN<0>")
	)
	(segment
		(start 324.85457 -234.705906)
		(end 324.678548 -234.705906)
		(width 0.18288)
		(layer "In2.Cu")
		(net "M_A_CPU0_SB_DQS_DN<0>")
	)
	(segment
		(start 323.338698 -233.190034)
		(end 322.950586 -232.801922)
		(width 0.18288)
		(layer "In2.Cu")
		(net "M_A_CPU0_SB_DQS_DN<0>")
	)
	(segment
		(start 319.142618 -228.993954)
		(end 318.966596 -228.993954)
		(width 0.18288)
		(layer "In2.Cu")
		(net "M_A_CPU0_SB_DQS_DN<0>")
	)
	(segment
		(start 318.578738 -228.606096)
		(end 317.909194 -228.606096)
		(width 0.18288)
		(layer "In2.Cu")
		(net "M_A_CPU0_SB_DQS_DN<0>")
	)
	(segment
		(start 320.09461 -229.945946)
		(end 319.918588 -229.945946)
		(width 0.18288)
		(layer "In2.Cu")
		(net "M_A_CPU0_SB_DQS_DN<0>")
	)
	(segment
		(start 333.078582 -237.736126)
		(end 333.06385 -237.72749)
		(width 0.088646)
		(layer "In2.Cu")
		(net "M_A_CPU0_SB_DQS_DN<0>")
	)
	(segment
		(start 314.553346 -228.606096)
		(end 314.288932 -228.341682)
		(width 0.18288)
		(layer "In2.Cu")
		(net "M_A_CPU0_SB_DQS_DN<0>")
	)
	(segment
		(start 310.262016 -228.186742)
		(end 309.992014 -227.91674)
		(width 0.18288)
		(layer "In2.Cu")
		(net "M_A_CPU0_SB_DQS_DN<0>")
	)
	(segment
		(start 317.909194 -228.606096)
		(end 317.784734 -228.481636)
		(width 0.18288)
		(layer "In2.Cu")
		(net "M_A_CPU0_SB_DQS_DN<0>")
	)
	(segment
		(start 314.185046 -228.341682)
		(end 314.014866 -228.341682)
		(width 0.16002)
		(layer "In2.Cu")
		(net "M_A_CPU0_SB_DQS_DN<0>")
	)
	(segment
		(start 321.998594 -231.84993)
		(end 321.822572 -231.84993)
		(width 0.18288)
		(layer "In2.Cu")
		(net "M_A_CPU0_SB_DQS_DN<0>")
	)
	(segment
		(start 318.966596 -228.993954)
		(end 318.578738 -228.606096)
		(width 0.18288)
		(layer "In2.Cu")
		(net "M_A_CPU0_SB_DQS_DN<0>")
	)
	(segment
		(start 325.242682 -235.094018)
		(end 324.85457 -234.705906)
		(width 0.18288)
		(layer "In2.Cu")
		(net "M_A_CPU0_SB_DQS_DN<0>")
	)
	(segment
		(start 320.482722 -230.51008)
		(end 320.482722 -230.334058)
		(width 0.18288)
		(layer "In2.Cu")
		(net "M_A_CPU0_SB_DQS_DN<0>")
	)
	(segment
		(start 320.87058 -230.897938)
		(end 320.482722 -230.51008)
		(width 0.18288)
		(layer "In2.Cu")
		(net "M_A_CPU0_SB_DQS_DN<0>")
	)
	(segment
		(start 312.14187 -228.216968)
		(end 312.14187 -228.200712)
		(width 0.16002)
		(layer "In2.Cu")
		(net "M_A_CPU0_SB_DQS_DN<0>")
	)
	(segment
		(start 312.527696 -228.586538)
		(end 312.385964 -228.444806)
		(width 0.18288)
		(layer "In2.Cu")
		(net "M_A_CPU0_SB_DQS_DN<0>")
	)
	(segment
		(start 336.085434 -237.411514)
		(end 335.901538 -237.59541)
		(width 0.088646)
		(layer "In2.Cu")
		(net "M_A_CPU0_SB_DQS_DN<0>")
	)
	(segment
		(start 315.765434 -228.606096)
		(end 314.553346 -228.606096)
		(width 0.18288)
		(layer "In2.Cu")
		(net "M_A_CPU0_SB_DQS_DN<0>")
	)
	(segment
		(start 319.918588 -229.945946)
		(end 319.53073 -229.558088)
		(width 0.18288)
		(layer "In2.Cu")
		(net "M_A_CPU0_SB_DQS_DN<0>")
	)
	(segment
		(start 311.872376 -227.931218)
		(end 311.227978 -227.931218)
		(width 0.18288)
		(layer "In2.Cu")
		(net "M_A_CPU0_SB_DQS_DN<0>")
	)
	(segment
		(start 320.482722 -230.334058)
		(end 320.09461 -229.945946)
		(width 0.18288)
		(layer "In2.Cu")
		(net "M_A_CPU0_SB_DQS_DN<0>")
	)
	(segment
		(start 321.434714 -231.28605)
		(end 321.046602 -230.897938)
		(width 0.18288)
		(layer "In2.Cu")
		(net "M_A_CPU0_SB_DQS_DN<0>")
	)
	(segment
		(start 322.950586 -232.801922)
		(end 322.774564 -232.801922)
		(width 0.18288)
		(layer "In2.Cu")
		(net "M_A_CPU0_SB_DQS_DN<0>")
	)
	(segment
		(start 322.386706 -232.414064)
		(end 322.386706 -232.238042)
		(width 0.18288)
		(layer "In2.Cu")
		(net "M_A_CPU0_SB_DQS_DN<0>")
	)
	(arc
		(start 334.008222 -237.73003)
		(mid 333.72979 -237.660184)
		(end 333.452978 -237.736126)
		(width 0.088646)
		(layer "In2.Cu")
		(net "M_A_CPU0_SB_DQS_DN<0>")
	)
	(arc
		(start 333.452978 -237.736126)
		(mid 333.26578 -237.786269)
		(end 333.078582 -237.736126)
		(width 0.088646)
		(layer "In2.Cu")
		(net "M_A_CPU0_SB_DQS_DN<0>")
	)
	(arc
		(start 334.393032 -237.736126)
		(mid 334.205834 -237.786269)
		(end 334.018636 -237.736126)
		(width 0.088646)
		(layer "In2.Cu")
		(net "M_A_CPU0_SB_DQS_DN<0>")
	)
	(arc
		(start 332.513178 -237.736126)
		(mid 332.32598 -237.786269)
		(end 332.138782 -237.736126)
		(width 0.088646)
		(layer "In2.Cu")
		(net "M_A_CPU0_SB_DQS_DN<0>")
	)
	(arc
		(start 334.947768 -237.73003)
		(mid 334.66959 -237.660307)
		(end 334.393032 -237.736126)
		(width 0.088646)
		(layer "In2.Cu")
		(net "M_A_CPU0_SB_DQS_DN<0>")
	)
	(arc
		(start 332.138782 -237.736126)
		(mid 331.972405 -237.66725)
		(end 331.79385 -237.643924)
		(width 0.088646)
		(layer "In2.Cu")
		(net "M_A_CPU0_SB_DQS_DN<0>")
	)
	(arc
		(start 333.06385 -237.72749)
		(mid 332.787375 -237.66017)
		(end 332.513178 -237.736126)
		(width 0.088646)
		(layer "In2.Cu")
		(net "M_A_CPU0_SB_DQS_DN<0>")
	)
	(arc
		(start 335.857342 -237.59541)
		(mid 335.585564 -237.631192)
		(end 335.332324 -237.736126)
		(width 0.088646)
		(layer "In2.Cu")
		(net "M_A_CPU0_SB_DQS_DN<0>")
	)
	(arc
		(start 335.332324 -237.736126)
		(mid 335.14527 -237.786142)
		(end 334.958182 -237.736126)
		(width 0.088646)
		(layer "In2.Cu")
		(net "M_A_CPU0_SB_DQS_DN<0>")
	)
	(segment
		(start 316.265052 -228.995224)
		(end 316.549024 -228.995224)
		(width 0.20066)
		(layer "F.Cu")
		(net "M_A_CPU0_SB_DQ<9>")
	)
	(segment
		(start 321.21602 -231.494076)
		(end 321.520312 -231.798368)
		(width 0.20066)
		(layer "F.Cu")
		(net "M_A_CPU0_SB_DQ<9>")
	)
	(segment
		(start 316.046104 -228.776276)
		(end 316.265052 -228.995224)
		(width 0.20066)
		(layer "F.Cu")
		(net "M_A_CPU0_SB_DQ<9>")
	)
	(segment
		(start 302.653446 -221.116652)
		(end 302.805084 -221.26829)
		(width 0.20066)
		(layer "F.Cu")
		(net "M_A_CPU0_SB_DQ<9>")
	)
	(segment
		(start 316.342014 -227.912422)
		(end 316.342014 -228.196394)
		(width 0.20066)
		(layer "F.Cu")
		(net "M_A_CPU0_SB_DQ<9>")
	)
	(segment
		(start 325.414386 -231.494076)
		(end 330.294996 -236.374686)
		(width 0.1016)
		(layer "F.Cu")
		(net "M_A_CPU0_SB_DQ<9>")
	)
	(segment
		(start 311.616852 -221.553024)
		(end 311.91708 -221.553024)
		(width 0.20066)
		(layer "F.Cu")
		(net "M_A_CPU0_SB_DQ<9>")
	)
	(segment
		(start 317.128906 -228.699314)
		(end 319.923668 -231.494076)
		(width 0.20066)
		(layer "F.Cu")
		(net "M_A_CPU0_SB_DQ<9>")
	)
	(segment
		(start 321.520312 -231.798368)
		(end 321.92722 -231.798368)
		(width 0.20066)
		(layer "F.Cu")
		(net "M_A_CPU0_SB_DQ<9>")
	)
	(segment
		(start 323.653912 -231.494076)
		(end 324.27291 -231.494076)
		(width 0.20066)
		(layer "F.Cu")
		(net "M_A_CPU0_SB_DQ<9>")
	)
	(segment
		(start 307.92928 -221.251272)
		(end 308.0639 -221.116652)
		(width 0.20066)
		(layer "F.Cu")
		(net "M_A_CPU0_SB_DQ<9>")
	)
	(segment
		(start 302.805084 -221.26829)
		(end 303.330356 -221.26829)
		(width 0.20066)
		(layer "F.Cu")
		(net "M_A_CPU0_SB_DQ<9>")
	)
	(segment
		(start 308.0639 -221.116652)
		(end 308.887114 -221.116652)
		(width 0.20066)
		(layer "F.Cu")
		(net "M_A_CPU0_SB_DQ<9>")
	)
	(segment
		(start 322.63842 -231.494076)
		(end 322.942712 -231.798368)
		(width 0.20066)
		(layer "F.Cu")
		(net "M_A_CPU0_SB_DQ<9>")
	)
	(segment
		(start 314.519818 -221.31147)
		(end 315.018166 -221.31147)
		(width 0.20066)
		(layer "F.Cu")
		(net "M_A_CPU0_SB_DQ<9>")
	)
	(segment
		(start 316.844934 -228.699314)
		(end 317.128906 -228.699314)
		(width 0.20066)
		(layer "F.Cu")
		(net "M_A_CPU0_SB_DQ<9>")
	)
	(segment
		(start 314.180982 -221.541594)
		(end 314.181998 -221.54261)
		(width 0.101854)
		(layer "F.Cu")
		(net "M_A_CPU0_SB_DQ<9>")
	)
	(segment
		(start 314.181998 -221.54261)
		(end 314.187078 -221.54261)
		(width 0.101854)
		(layer "F.Cu")
		(net "M_A_CPU0_SB_DQ<9>")
	)
	(segment
		(start 315.957204 -222.250508)
		(end 315.957204 -227.527612)
		(width 0.20066)
		(layer "F.Cu")
		(net "M_A_CPU0_SB_DQ<9>")
	)
	(segment
		(start 309.974742 -221.116652)
		(end 310.968898 -221.333314)
		(width 0.20066)
		(layer "F.Cu")
		(net "M_A_CPU0_SB_DQ<9>")
	)
	(segment
		(start 306.244752 -220.69171)
		(end 306.644294 -220.69171)
		(width 0.101854)
		(layer "F.Cu")
		(net "M_A_CPU0_SB_DQ<9>")
	)
	(segment
		(start 308.887114 -221.116652)
		(end 309.974742 -221.116652)
		(width 0.20066)
		(layer "F.Cu")
		(net "M_A_CPU0_SB_DQ<9>")
	)
	(segment
		(start 304.329084 -220.69171)
		(end 304.550826 -220.69171)
		(width 0.101854)
		(layer "F.Cu")
		(net "M_A_CPU0_SB_DQ<9>")
	)
	(segment
		(start 304.550826 -220.69171)
		(end 306.244752 -220.69171)
		(width 0.1016)
		(layer "F.Cu")
		(net "M_A_CPU0_SB_DQ<9>")
	)
	(segment
		(start 304.319178 -220.681804)
		(end 304.329084 -220.69171)
		(width 0.101854)
		(layer "F.Cu")
		(net "M_A_CPU0_SB_DQ<9>")
	)
	(segment
		(start 316.342014 -228.196394)
		(end 316.046104 -228.492304)
		(width 0.20066)
		(layer "F.Cu")
		(net "M_A_CPU0_SB_DQ<9>")
	)
	(segment
		(start 310.968898 -221.333314)
		(end 311.616852 -221.553024)
		(width 0.20066)
		(layer "F.Cu")
		(net "M_A_CPU0_SB_DQ<9>")
	)
	(segment
		(start 303.523396 -221.07525)
		(end 303.523396 -220.846142)
		(width 0.20066)
		(layer "F.Cu")
		(net "M_A_CPU0_SB_DQ<9>")
	)
	(segment
		(start 315.018166 -221.31147)
		(end 315.957204 -222.250508)
		(width 0.20066)
		(layer "F.Cu")
		(net "M_A_CPU0_SB_DQ<9>")
	)
	(segment
		(start 331.461364 -236.374686)
		(end 331.691234 -236.374686)
		(width 0.088646)
		(layer "F.Cu")
		(net "M_A_CPU0_SB_DQ<9>")
	)
	(segment
		(start 303.687734 -220.681804)
		(end 304.319178 -220.681804)
		(width 0.20066)
		(layer "F.Cu")
		(net "M_A_CPU0_SB_DQ<9>")
	)
	(segment
		(start 306.644294 -220.69171)
		(end 306.714652 -220.69171)
		(width 0.20066)
		(layer "F.Cu")
		(net "M_A_CPU0_SB_DQ<9>")
	)
	(segment
		(start 323.34962 -231.798368)
		(end 323.653912 -231.494076)
		(width 0.20066)
		(layer "F.Cu")
		(net "M_A_CPU0_SB_DQ<9>")
	)
	(segment
		(start 331.746098 -236.319822)
		(end 333.26578 -236.319822)
		(width 0.088646)
		(layer "F.Cu")
		(net "M_A_CPU0_SB_DQ<9>")
	)
	(segment
		(start 321.92722 -231.798368)
		(end 322.231512 -231.494076)
		(width 0.20066)
		(layer "F.Cu")
		(net "M_A_CPU0_SB_DQ<9>")
	)
	(segment
		(start 330.294996 -236.374686)
		(end 331.461364 -236.374686)
		(width 0.1016)
		(layer "F.Cu")
		(net "M_A_CPU0_SB_DQ<9>")
	)
	(segment
		(start 322.231512 -231.494076)
		(end 322.63842 -231.494076)
		(width 0.20066)
		(layer "F.Cu")
		(net "M_A_CPU0_SB_DQ<9>")
	)
	(segment
		(start 316.046104 -228.492304)
		(end 316.046104 -228.776276)
		(width 0.20066)
		(layer "F.Cu")
		(net "M_A_CPU0_SB_DQ<9>")
	)
	(segment
		(start 303.330356 -221.26829)
		(end 303.523396 -221.07525)
		(width 0.20066)
		(layer "F.Cu")
		(net "M_A_CPU0_SB_DQ<9>")
	)
	(segment
		(start 331.691234 -236.374686)
		(end 331.746098 -236.319822)
		(width 0.088646)
		(layer "F.Cu")
		(net "M_A_CPU0_SB_DQ<9>")
	)
	(segment
		(start 303.523396 -220.846142)
		(end 303.687734 -220.681804)
		(width 0.20066)
		(layer "F.Cu")
		(net "M_A_CPU0_SB_DQ<9>")
	)
	(segment
		(start 313.79541 -221.541594)
		(end 314.180982 -221.541594)
		(width 0.101854)
		(layer "F.Cu")
		(net "M_A_CPU0_SB_DQ<9>")
	)
	(segment
		(start 306.714652 -220.69171)
		(end 307.274214 -221.251272)
		(width 0.20066)
		(layer "F.Cu")
		(net "M_A_CPU0_SB_DQ<9>")
	)
	(segment
		(start 315.957204 -227.527612)
		(end 316.342014 -227.912422)
		(width 0.20066)
		(layer "F.Cu")
		(net "M_A_CPU0_SB_DQ<9>")
	)
	(segment
		(start 316.549024 -228.995224)
		(end 316.844934 -228.699314)
		(width 0.20066)
		(layer "F.Cu")
		(net "M_A_CPU0_SB_DQ<9>")
	)
	(segment
		(start 311.91708 -221.553024)
		(end 311.92851 -221.541594)
		(width 0.1016)
		(layer "F.Cu")
		(net "M_A_CPU0_SB_DQ<9>")
	)
	(segment
		(start 324.27291 -231.494076)
		(end 325.414386 -231.494076)
		(width 0.1016)
		(layer "F.Cu")
		(net "M_A_CPU0_SB_DQ<9>")
	)
	(segment
		(start 322.942712 -231.798368)
		(end 323.34962 -231.798368)
		(width 0.20066)
		(layer "F.Cu")
		(net "M_A_CPU0_SB_DQ<9>")
	)
	(segment
		(start 301.343314 -221.116652)
		(end 302.653446 -221.116652)
		(width 0.20066)
		(layer "F.Cu")
		(net "M_A_CPU0_SB_DQ<9>")
	)
	(segment
		(start 319.923668 -231.494076)
		(end 321.21602 -231.494076)
		(width 0.20066)
		(layer "F.Cu")
		(net "M_A_CPU0_SB_DQ<9>")
	)
	(segment
		(start 314.187078 -221.54261)
		(end 314.288678 -221.54261)
		(width 0.20066)
		(layer "F.Cu")
		(net "M_A_CPU0_SB_DQ<9>")
	)
	(segment
		(start 314.288678 -221.54261)
		(end 314.519818 -221.31147)
		(width 0.20066)
		(layer "F.Cu")
		(net "M_A_CPU0_SB_DQ<9>")
	)
	(segment
		(start 311.92851 -221.541594)
		(end 313.79541 -221.541594)
		(width 0.1016)
		(layer "F.Cu")
		(net "M_A_CPU0_SB_DQ<9>")
	)
	(segment
		(start 307.274214 -221.251272)
		(end 307.92928 -221.251272)
		(width 0.20066)
		(layer "F.Cu")
		(net "M_A_CPU0_SB_DQ<9>")
	)
	(segment
		(start 303.523396 -222.739204)
		(end 303.523396 -222.546164)
		(width 0.20066)
		(layer "F.Cu")
		(net "M_A_CPU0_SB_DQ<8>")
	)
	(segment
		(start 311.573926 -222.483172)
		(end 311.00776 -222.483172)
		(width 0.20066)
		(layer "F.Cu")
		(net "M_A_CPU0_SB_DQ<8>")
	)
	(segment
		(start 311.00776 -222.483172)
		(end 310.674258 -222.816674)
		(width 0.20066)
		(layer "F.Cu")
		(net "M_A_CPU0_SB_DQ<8>")
	)
	(segment
		(start 314.261246 -222.372682)
		(end 314.12688 -222.372682)
		(width 0.20066)
		(layer "F.Cu")
		(net "M_A_CPU0_SB_DQ<8>")
	)
	(segment
		(start 311.673494 -222.383604)
		(end 311.573926 -222.483172)
		(width 0.20066)
		(layer "F.Cu")
		(net "M_A_CPU0_SB_DQ<8>")
	)
	(segment
		(start 304.33264 -222.391732)
		(end 304.550826 -222.391732)
		(width 0.101854)
		(layer "F.Cu")
		(net "M_A_CPU0_SB_DQ<8>")
	)
	(segment
		(start 311.925208 -222.391732)
		(end 311.91708 -222.383604)
		(width 0.101854)
		(layer "F.Cu")
		(net "M_A_CPU0_SB_DQ<8>")
	)
	(segment
		(start 330.042012 -236.984286)
		(end 326.16775 -233.110024)
		(width 0.1016)
		(layer "F.Cu")
		(net "M_A_CPU0_SB_DQ<8>")
	)
	(segment
		(start 302.448214 -222.816674)
		(end 302.624744 -222.993204)
		(width 0.20066)
		(layer "F.Cu")
		(net "M_A_CPU0_SB_DQ<8>")
	)
	(segment
		(start 326.16775 -233.110024)
		(end 325.746364 -233.110024)
		(width 0.1016)
		(layer "F.Cu")
		(net "M_A_CPU0_SB_DQ<8>")
	)
	(segment
		(start 312.12536 -222.391732)
		(end 311.925208 -222.391732)
		(width 0.101854)
		(layer "F.Cu")
		(net "M_A_CPU0_SB_DQ<8>")
	)
	(segment
		(start 302.624744 -222.993204)
		(end 303.269396 -222.993204)
		(width 0.20066)
		(layer "F.Cu")
		(net "M_A_CPU0_SB_DQ<8>")
	)
	(segment
		(start 308.094634 -222.816674)
		(end 308.887114 -222.816674)
		(width 0.20066)
		(layer "F.Cu")
		(net "M_A_CPU0_SB_DQ<8>")
	)
	(segment
		(start 331.993494 -236.732826)
		(end 331.742034 -236.984286)
		(width 0.088646)
		(layer "F.Cu")
		(net "M_A_CPU0_SB_DQ<8>")
	)
	(segment
		(start 333.349092 -237.03026)
		(end 332.967584 -236.809788)
		(width 0.088646)
		(layer "F.Cu")
		(net "M_A_CPU0_SB_DQ<8>")
	)
	(segment
		(start 331.742034 -236.984286)
		(end 331.461364 -236.984286)
		(width 0.088646)
		(layer "F.Cu")
		(net "M_A_CPU0_SB_DQ<8>")
	)
	(segment
		(start 307.995066 -222.916242)
		(end 308.094634 -222.816674)
		(width 0.20066)
		(layer "F.Cu")
		(net "M_A_CPU0_SB_DQ<8>")
	)
	(segment
		(start 310.674258 -222.816674)
		(end 308.887114 -222.816674)
		(width 0.20066)
		(layer "F.Cu")
		(net "M_A_CPU0_SB_DQ<8>")
	)
	(segment
		(start 303.69129 -222.37827)
		(end 304.319178 -222.37827)
		(width 0.20066)
		(layer "F.Cu")
		(net "M_A_CPU0_SB_DQ<8>")
	)
	(segment
		(start 306.644294 -222.378778)
		(end 306.74183 -222.378778)
		(width 0.20066)
		(layer "F.Cu")
		(net "M_A_CPU0_SB_DQ<8>")
	)
	(segment
		(start 314.069984 -222.391732)
		(end 312.12536 -222.391732)
		(width 0.1016)
		(layer "F.Cu")
		(net "M_A_CPU0_SB_DQ<8>")
	)
	(segment
		(start 306.74183 -222.378778)
		(end 307.279294 -222.916242)
		(width 0.20066)
		(layer "F.Cu")
		(net "M_A_CPU0_SB_DQ<8>")
	)
	(segment
		(start 303.269396 -222.993204)
		(end 303.523396 -222.739204)
		(width 0.20066)
		(layer "F.Cu")
		(net "M_A_CPU0_SB_DQ<8>")
	)
	(segment
		(start 306.63134 -222.391732)
		(end 306.644294 -222.378778)
		(width 0.101854)
		(layer "F.Cu")
		(net "M_A_CPU0_SB_DQ<8>")
	)
	(segment
		(start 314.089034 -222.372682)
		(end 314.069984 -222.391732)
		(width 0.101854)
		(layer "F.Cu")
		(net "M_A_CPU0_SB_DQ<8>")
	)
	(segment
		(start 307.279294 -222.916242)
		(end 307.995066 -222.916242)
		(width 0.20066)
		(layer "F.Cu")
		(net "M_A_CPU0_SB_DQ<8>")
	)
	(segment
		(start 311.91708 -222.383604)
		(end 311.673494 -222.383604)
		(width 0.20066)
		(layer "F.Cu")
		(net "M_A_CPU0_SB_DQ<8>")
	)
	(segment
		(start 318.060324 -233.110024)
		(end 314.648088 -229.697788)
		(width 0.20066)
		(layer "F.Cu")
		(net "M_A_CPU0_SB_DQ<8>")
	)
	(segment
		(start 306.289202 -222.391732)
		(end 306.63134 -222.391732)
		(width 0.101854)
		(layer "F.Cu")
		(net "M_A_CPU0_SB_DQ<8>")
	)
	(segment
		(start 331.461364 -236.984286)
		(end 330.042012 -236.984286)
		(width 0.1016)
		(layer "F.Cu")
		(net "M_A_CPU0_SB_DQ<8>")
	)
	(segment
		(start 303.523396 -222.546164)
		(end 303.69129 -222.37827)
		(width 0.20066)
		(layer "F.Cu")
		(net "M_A_CPU0_SB_DQ<8>")
	)
	(segment
		(start 314.648088 -222.759524)
		(end 314.261246 -222.372682)
		(width 0.20066)
		(layer "F.Cu")
		(net "M_A_CPU0_SB_DQ<8>")
	)
	(segment
		(start 304.319178 -222.37827)
		(end 304.33264 -222.391732)
		(width 0.101854)
		(layer "F.Cu")
		(net "M_A_CPU0_SB_DQ<8>")
	)
	(segment
		(start 332.671928 -236.732826)
		(end 331.993494 -236.732826)
		(width 0.088646)
		(layer "F.Cu")
		(net "M_A_CPU0_SB_DQ<8>")
	)
	(segment
		(start 301.343314 -222.816674)
		(end 302.448214 -222.816674)
		(width 0.20066)
		(layer "F.Cu")
		(net "M_A_CPU0_SB_DQ<8>")
	)
	(segment
		(start 304.550826 -222.391732)
		(end 306.289202 -222.391732)
		(width 0.1016)
		(layer "F.Cu")
		(net "M_A_CPU0_SB_DQ<8>")
	)
	(segment
		(start 325.746364 -233.110024)
		(end 318.060324 -233.110024)
		(width 0.20066)
		(layer "F.Cu")
		(net "M_A_CPU0_SB_DQ<8>")
	)
	(segment
		(start 314.648088 -229.697788)
		(end 314.648088 -222.759524)
		(width 0.20066)
		(layer "F.Cu")
		(net "M_A_CPU0_SB_DQ<8>")
	)
	(segment
		(start 314.12688 -222.372682)
		(end 314.089034 -222.372682)
		(width 0.101854)
		(layer "F.Cu")
		(net "M_A_CPU0_SB_DQ<8>")
	)
	(arc
		(start 332.967584 -236.809788)
		(mid 332.824688 -236.752351)
		(end 332.671928 -236.732826)
		(width 0.088646)
		(layer "F.Cu")
		(net "M_A_CPU0_SB_DQ<8>")
	)
	(arc
		(start 333.735934 -237.133892)
		(mid 333.535667 -237.107615)
		(end 333.349092 -237.03026)
		(width 0.088646)
		(layer "F.Cu")
		(net "M_A_CPU0_SB_DQ<8>")
	)
	(segment
		(start 310.609996 -223.964246)
		(end 310.48198 -224.092262)
		(width 0.20066)
		(layer "F.Cu")
		(net "M_A_CPU0_SB_DQ<7>")
	)
	(segment
		(start 307.76291 -224.109026)
		(end 307.449474 -224.109026)
		(width 0.20066)
		(layer "F.Cu")
		(net "M_A_CPU0_SB_DQ<7>")
	)
	(segment
		(start 309.77967 -224.092262)
		(end 309.778908 -224.0915)
		(width 0.1016)
		(layer "F.Cu")
		(net "M_A_CPU0_SB_DQ<7>")
	)
	(segment
		(start 314.092082 -223.666558)
		(end 312.987182 -223.666558)
		(width 0.20066)
		(layer "F.Cu")
		(net "M_A_CPU0_SB_DQ<7>")
	)
	(segment
		(start 337.96478 -236.319822)
		(end 337.965034 -236.319568)
		(width 0.20066)
		(layer "F.Cu")
		(net "M_A_CPU0_SB_DQ<7>")
	)
	(segment
		(start 311.645554 -223.666558)
		(end 311.405778 -223.426782)
		(width 0.20066)
		(layer "F.Cu")
		(net "M_A_CPU0_SB_DQ<7>")
	)
	(segment
		(start 311.405778 -223.426782)
		(end 310.874156 -223.426782)
		(width 0.20066)
		(layer "F.Cu")
		(net "M_A_CPU0_SB_DQ<7>")
	)
	(segment
		(start 310.088026 -224.092262)
		(end 310.01208 -224.092262)
		(width 0.101854)
		(layer "F.Cu")
		(net "M_A_CPU0_SB_DQ<7>")
	)
	(segment
		(start 310.874156 -223.426782)
		(end 310.609996 -223.690942)
		(width 0.20066)
		(layer "F.Cu")
		(net "M_A_CPU0_SB_DQ<7>")
	)
	(segment
		(start 312.987182 -223.666558)
		(end 311.645554 -223.666558)
		(width 0.20066)
		(layer "F.Cu")
		(net "M_A_CPU0_SB_DQ<7>")
	)
	(segment
		(start 310.609996 -223.690942)
		(end 310.609996 -223.964246)
		(width 0.20066)
		(layer "F.Cu")
		(net "M_A_CPU0_SB_DQ<7>")
	)
	(segment
		(start 337.965034 -236.319568)
		(end 337.965034 -235.783882)
		(width 0.20066)
		(layer "F.Cu")
		(net "M_A_CPU0_SB_DQ<7>")
	)
	(segment
		(start 310.48198 -224.092262)
		(end 310.088026 -224.092262)
		(width 0.20066)
		(layer "F.Cu")
		(net "M_A_CPU0_SB_DQ<7>")
	)
	(segment
		(start 307.007006 -223.666558)
		(end 305.443382 -223.666558)
		(width 0.20066)
		(layer "F.Cu")
		(net "M_A_CPU0_SB_DQ<7>")
	)
	(segment
		(start 307.85308 -224.0915)
		(end 307.795422 -224.0915)
		(width 0.101854)
		(layer "F.Cu")
		(net "M_A_CPU0_SB_DQ<7>")
	)
	(segment
		(start 310.01208 -224.092262)
		(end 309.77967 -224.092262)
		(width 0.1016)
		(layer "F.Cu")
		(net "M_A_CPU0_SB_DQ<7>")
	)
	(segment
		(start 309.778908 -224.0915)
		(end 307.85308 -224.0915)
		(width 0.1016)
		(layer "F.Cu")
		(net "M_A_CPU0_SB_DQ<7>")
	)
	(segment
		(start 307.777896 -224.109026)
		(end 307.76291 -224.109026)
		(width 0.101854)
		(layer "F.Cu")
		(net "M_A_CPU0_SB_DQ<7>")
	)
	(segment
		(start 307.795422 -224.0915)
		(end 307.777896 -224.109026)
		(width 0.101854)
		(layer "F.Cu")
		(net "M_A_CPU0_SB_DQ<7>")
	)
	(segment
		(start 307.449474 -224.109026)
		(end 307.007006 -223.666558)
		(width 0.20066)
		(layer "F.Cu")
		(net "M_A_CPU0_SB_DQ<7>")
	)
	(segment
		(start 316.31382 -224.113852)
		(end 316.31382 -223.740218)
		(width 0.18288)
		(layer "In2.Cu")
		(net "M_A_CPU0_SB_DQ<7>")
	)
	(segment
		(start 331.53223 -235.530898)
		(end 330.699364 -235.530898)
		(width 0.088646)
		(layer "In2.Cu")
		(net "M_A_CPU0_SB_DQ<7>")
	)
	(segment
		(start 317.72606 -224.113852)
		(end 317.72606 -223.722692)
		(width 0.18288)
		(layer "In2.Cu")
		(net "M_A_CPU0_SB_DQ<7>")
	)
	(segment
		(start 317.21298 -223.529652)
		(end 317.01994 -223.722692)
		(width 0.18288)
		(layer "In2.Cu")
		(net "M_A_CPU0_SB_DQ<7>")
	)
	(segment
		(start 331.53731 -235.535978)
		(end 331.53223 -235.530898)
		(width 0.088646)
		(layer "In2.Cu")
		(net "M_A_CPU0_SB_DQ<7>")
	)
	(segment
		(start 336.367882 -235.294424)
		(end 336.35315 -235.285788)
		(width 0.088646)
		(layer "In2.Cu")
		(net "M_A_CPU0_SB_DQ<7>")
	)
	(segment
		(start 315.80074 -223.529652)
		(end 315.6077 -223.722692)
		(width 0.18288)
		(layer "In2.Cu")
		(net "M_A_CPU0_SB_DQ<7>")
	)
	(segment
		(start 317.01994 -223.722692)
		(end 317.01994 -224.113852)
		(width 0.18288)
		(layer "In2.Cu")
		(net "M_A_CPU0_SB_DQ<7>")
	)
	(segment
		(start 314.837826 -224.160334)
		(end 314.837826 -223.73463)
		(width 0.18288)
		(layer "In2.Cu")
		(net "M_A_CPU0_SB_DQ<7>")
	)
	(segment
		(start 337.307682 -235.29417)
		(end 337.307682 -235.294424)
		(width 0.088646)
		(layer "In2.Cu")
		(net "M_A_CPU0_SB_DQ<7>")
	)
	(segment
		(start 314.42279 -223.529652)
		(end 314.092082 -223.666558)
		(width 0.18288)
		(layer "In2.Cu")
		(net "M_A_CPU0_SB_DQ<7>")
	)
	(segment
		(start 315.6077 -223.722692)
		(end 315.6077 -224.113852)
		(width 0.18288)
		(layer "In2.Cu")
		(net "M_A_CPU0_SB_DQ<7>")
	)
	(segment
		(start 330.699364 -235.530898)
		(end 329.76566 -235.530898)
		(width 0.18288)
		(layer "In2.Cu")
		(net "M_A_CPU0_SB_DQ<7>")
	)
	(segment
		(start 316.31382 -223.740218)
		(end 316.103254 -223.529652)
		(width 0.18288)
		(layer "In2.Cu")
		(net "M_A_CPU0_SB_DQ<7>")
	)
	(segment
		(start 317.9191 -224.306892)
		(end 317.72606 -224.113852)
		(width 0.18288)
		(layer "In2.Cu")
		(net "M_A_CPU0_SB_DQ<7>")
	)
	(segment
		(start 317.72606 -223.722692)
		(end 317.53302 -223.529652)
		(width 0.18288)
		(layer "In2.Cu")
		(net "M_A_CPU0_SB_DQ<7>")
	)
	(segment
		(start 337.307682 -235.294424)
		(end 337.29295 -235.285788)
		(width 0.088646)
		(layer "In2.Cu")
		(net "M_A_CPU0_SB_DQ<7>")
	)
	(segment
		(start 332.608682 -235.294424)
		(end 332.59395 -235.285788)
		(width 0.088646)
		(layer "In2.Cu")
		(net "M_A_CPU0_SB_DQ<7>")
	)
	(segment
		(start 315.6077 -224.113852)
		(end 315.41466 -224.306892)
		(width 0.18288)
		(layer "In2.Cu")
		(net "M_A_CPU0_SB_DQ<7>")
	)
	(segment
		(start 331.926438 -235.384086)
		(end 331.774546 -235.535978)
		(width 0.088646)
		(layer "In2.Cu")
		(net "M_A_CPU0_SB_DQ<7>")
	)
	(segment
		(start 315.41466 -224.306892)
		(end 314.984384 -224.306892)
		(width 0.18288)
		(layer "In2.Cu")
		(net "M_A_CPU0_SB_DQ<7>")
	)
	(segment
		(start 317.01994 -224.113852)
		(end 316.8269 -224.306892)
		(width 0.18288)
		(layer "In2.Cu")
		(net "M_A_CPU0_SB_DQ<7>")
	)
	(segment
		(start 335.428082 -235.294424)
		(end 335.41335 -235.285788)
		(width 0.088646)
		(layer "In2.Cu")
		(net "M_A_CPU0_SB_DQ<7>")
	)
	(segment
		(start 334.488282 -235.294424)
		(end 334.47355 -235.285788)
		(width 0.088646)
		(layer "In2.Cu")
		(net "M_A_CPU0_SB_DQ<7>")
	)
	(segment
		(start 314.837826 -223.73463)
		(end 314.632848 -223.529652)
		(width 0.18288)
		(layer "In2.Cu")
		(net "M_A_CPU0_SB_DQ<7>")
	)
	(segment
		(start 316.8269 -224.306892)
		(end 316.50686 -224.306892)
		(width 0.18288)
		(layer "In2.Cu")
		(net "M_A_CPU0_SB_DQ<7>")
	)
	(segment
		(start 317.53302 -223.529652)
		(end 317.21298 -223.529652)
		(width 0.18288)
		(layer "In2.Cu")
		(net "M_A_CPU0_SB_DQ<7>")
	)
	(segment
		(start 337.651852 -235.783882)
		(end 337.586828 -235.718858)
		(width 0.088646)
		(layer "In2.Cu")
		(net "M_A_CPU0_SB_DQ<7>")
	)
	(segment
		(start 314.984384 -224.306892)
		(end 314.837826 -224.160334)
		(width 0.18288)
		(layer "In2.Cu")
		(net "M_A_CPU0_SB_DQ<7>")
	)
	(segment
		(start 314.632848 -223.529652)
		(end 314.42279 -223.529652)
		(width 0.18288)
		(layer "In2.Cu")
		(net "M_A_CPU0_SB_DQ<7>")
	)
	(segment
		(start 333.548482 -235.294424)
		(end 333.53375 -235.285788)
		(width 0.088646)
		(layer "In2.Cu")
		(net "M_A_CPU0_SB_DQ<7>")
	)
	(segment
		(start 318.541654 -224.306892)
		(end 317.9191 -224.306892)
		(width 0.18288)
		(layer "In2.Cu")
		(net "M_A_CPU0_SB_DQ<7>")
	)
	(segment
		(start 316.50686 -224.306892)
		(end 316.31382 -224.113852)
		(width 0.18288)
		(layer "In2.Cu")
		(net "M_A_CPU0_SB_DQ<7>")
	)
	(segment
		(start 331.774546 -235.535978)
		(end 331.53731 -235.535978)
		(width 0.088646)
		(layer "In2.Cu")
		(net "M_A_CPU0_SB_DQ<7>")
	)
	(segment
		(start 337.965034 -235.783882)
		(end 337.651852 -235.783882)
		(width 0.088646)
		(layer "In2.Cu")
		(net "M_A_CPU0_SB_DQ<7>")
	)
	(segment
		(start 329.76566 -235.530898)
		(end 318.541654 -224.306892)
		(width 0.18288)
		(layer "In2.Cu")
		(net "M_A_CPU0_SB_DQ<7>")
	)
	(segment
		(start 316.103254 -223.529652)
		(end 315.80074 -223.529652)
		(width 0.18288)
		(layer "In2.Cu")
		(net "M_A_CPU0_SB_DQ<7>")
	)
	(arc
		(start 336.35315 -235.285788)
		(mid 336.076675 -235.218468)
		(end 335.802478 -235.294424)
		(width 0.088646)
		(layer "In2.Cu")
		(net "M_A_CPU0_SB_DQ<7>")
	)
	(arc
		(start 333.922878 -235.294424)
		(mid 333.73568 -235.344567)
		(end 333.548482 -235.294424)
		(width 0.088646)
		(layer "In2.Cu")
		(net "M_A_CPU0_SB_DQ<7>")
	)
	(arc
		(start 335.41335 -235.285788)
		(mid 335.136875 -235.218468)
		(end 334.862678 -235.294424)
		(width 0.088646)
		(layer "In2.Cu")
		(net "M_A_CPU0_SB_DQ<7>")
	)
	(arc
		(start 337.29295 -235.285788)
		(mid 337.016475 -235.218468)
		(end 336.742278 -235.294424)
		(width 0.088646)
		(layer "In2.Cu")
		(net "M_A_CPU0_SB_DQ<7>")
	)
	(arc
		(start 332.043278 -235.294424)
		(mid 331.981938 -235.335448)
		(end 331.926438 -235.384086)
		(width 0.088646)
		(layer "In2.Cu")
		(net "M_A_CPU0_SB_DQ<7>")
	)
	(arc
		(start 332.983078 -235.294424)
		(mid 332.79588 -235.344567)
		(end 332.608682 -235.294424)
		(width 0.088646)
		(layer "In2.Cu")
		(net "M_A_CPU0_SB_DQ<7>")
	)
	(arc
		(start 337.586828 -235.718858)
		(mid 337.497674 -235.473371)
		(end 337.307682 -235.29417)
		(width 0.088646)
		(layer "In2.Cu")
		(net "M_A_CPU0_SB_DQ<7>")
	)
	(arc
		(start 336.742278 -235.294424)
		(mid 336.55508 -235.344567)
		(end 336.367882 -235.294424)
		(width 0.088646)
		(layer "In2.Cu")
		(net "M_A_CPU0_SB_DQ<7>")
	)
	(arc
		(start 335.802478 -235.294424)
		(mid 335.61528 -235.344567)
		(end 335.428082 -235.294424)
		(width 0.088646)
		(layer "In2.Cu")
		(net "M_A_CPU0_SB_DQ<7>")
	)
	(arc
		(start 334.862678 -235.294424)
		(mid 334.67548 -235.344567)
		(end 334.488282 -235.294424)
		(width 0.088646)
		(layer "In2.Cu")
		(net "M_A_CPU0_SB_DQ<7>")
	)
	(arc
		(start 333.53375 -235.285788)
		(mid 333.257275 -235.218468)
		(end 332.983078 -235.294424)
		(width 0.088646)
		(layer "In2.Cu")
		(net "M_A_CPU0_SB_DQ<7>")
	)
	(arc
		(start 334.47355 -235.285788)
		(mid 334.197075 -235.218468)
		(end 333.922878 -235.294424)
		(width 0.088646)
		(layer "In2.Cu")
		(net "M_A_CPU0_SB_DQ<7>")
	)
	(arc
		(start 332.59395 -235.285788)
		(mid 332.317475 -235.218468)
		(end 332.043278 -235.294424)
		(width 0.088646)
		(layer "In2.Cu")
		(net "M_A_CPU0_SB_DQ<7>")
	)
	(segment
		(start 307.76291 -225.808794)
		(end 307.485288 -225.808794)
		(width 0.20066)
		(layer "F.Cu")
		(net "M_A_CPU0_SB_DQ<6>")
	)
	(segment
		(start 307.042566 -225.366072)
		(end 307.042058 -225.36658)
		(width 0.20066)
		(layer "F.Cu")
		(net "M_A_CPU0_SB_DQ<6>")
	)
	(segment
		(start 310.088026 -225.791776)
		(end 310.01208 -225.791776)
		(width 0.101854)
		(layer "F.Cu")
		(net "M_A_CPU0_SB_DQ<6>")
	)
	(segment
		(start 307.814472 -225.808794)
		(end 307.76291 -225.808794)
		(width 0.101854)
		(layer "F.Cu")
		(net "M_A_CPU0_SB_DQ<6>")
	)
	(segment
		(start 311.491122 -225.36658)
		(end 311.26938 -225.144838)
		(width 0.20066)
		(layer "F.Cu")
		(net "M_A_CPU0_SB_DQ<6>")
	)
	(segment
		(start 307.83149 -225.791776)
		(end 307.814472 -225.808794)
		(width 0.101854)
		(layer "F.Cu")
		(net "M_A_CPU0_SB_DQ<6>")
	)
	(segment
		(start 338.43468 -237.133638)
		(end 338.43468 -236.597952)
		(width 0.20066)
		(layer "F.Cu")
		(net "M_A_CPU0_SB_DQ<6>")
	)
	(segment
		(start 310.609996 -225.3107)
		(end 310.609996 -225.664268)
		(width 0.20066)
		(layer "F.Cu")
		(net "M_A_CPU0_SB_DQ<6>")
	)
	(segment
		(start 310.609996 -225.664268)
		(end 310.482488 -225.791776)
		(width 0.20066)
		(layer "F.Cu")
		(net "M_A_CPU0_SB_DQ<6>")
	)
	(segment
		(start 338.434934 -237.133892)
		(end 338.43468 -237.133638)
		(width 0.20066)
		(layer "F.Cu")
		(net "M_A_CPU0_SB_DQ<6>")
	)
	(segment
		(start 312.987182 -225.36658)
		(end 311.491122 -225.36658)
		(width 0.20066)
		(layer "F.Cu")
		(net "M_A_CPU0_SB_DQ<6>")
	)
	(segment
		(start 307.85308 -225.791776)
		(end 307.83149 -225.791776)
		(width 0.101854)
		(layer "F.Cu")
		(net "M_A_CPU0_SB_DQ<6>")
	)
	(segment
		(start 314.092082 -225.36658)
		(end 312.987182 -225.36658)
		(width 0.20066)
		(layer "F.Cu")
		(net "M_A_CPU0_SB_DQ<6>")
	)
	(segment
		(start 307.042058 -225.36658)
		(end 305.443382 -225.36658)
		(width 0.20066)
		(layer "F.Cu")
		(net "M_A_CPU0_SB_DQ<6>")
	)
	(segment
		(start 307.485288 -225.808794)
		(end 307.042566 -225.366072)
		(width 0.20066)
		(layer "F.Cu")
		(net "M_A_CPU0_SB_DQ<6>")
	)
	(segment
		(start 310.775858 -225.144838)
		(end 310.609996 -225.3107)
		(width 0.20066)
		(layer "F.Cu")
		(net "M_A_CPU0_SB_DQ<6>")
	)
	(segment
		(start 310.01208 -225.791776)
		(end 307.85308 -225.791776)
		(width 0.1016)
		(layer "F.Cu")
		(net "M_A_CPU0_SB_DQ<6>")
	)
	(segment
		(start 310.482488 -225.791776)
		(end 310.088026 -225.791776)
		(width 0.20066)
		(layer "F.Cu")
		(net "M_A_CPU0_SB_DQ<6>")
	)
	(segment
		(start 311.26938 -225.144838)
		(end 310.775858 -225.144838)
		(width 0.20066)
		(layer "F.Cu")
		(net "M_A_CPU0_SB_DQ<6>")
	)
	(segment
		(start 315.426598 -226.095814)
		(end 315.426598 -225.55962)
		(width 0.18288)
		(layer "In2.Cu")
		(net "M_A_CPU0_SB_DQ<6>")
	)
	(segment
		(start 330.699364 -236.221778)
		(end 328.999088 -236.221778)
		(width 0.18288)
		(layer "In2.Cu")
		(net "M_A_CPU0_SB_DQ<6>")
	)
	(segment
		(start 316.862714 -226.095814)
		(end 316.862714 -225.630232)
		(width 0.18288)
		(layer "In2.Cu")
		(net "M_A_CPU0_SB_DQ<6>")
	)
	(segment
		(start 317.761874 -225.423984)
		(end 317.568834 -225.617024)
		(width 0.18288)
		(layer "In2.Cu")
		(net "M_A_CPU0_SB_DQ<6>")
	)
	(segment
		(start 317.375794 -226.288854)
		(end 317.055754 -226.288854)
		(width 0.18288)
		(layer "In2.Cu")
		(net "M_A_CPU0_SB_DQ<6>")
	)
	(segment
		(start 319.066164 -226.288854)
		(end 318.467994 -226.288854)
		(width 0.18288)
		(layer "In2.Cu")
		(net "M_A_CPU0_SB_DQ<6>")
	)
	(segment
		(start 331.57795 -236.221778)
		(end 330.699364 -236.221778)
		(width 0.088646)
		(layer "In2.Cu")
		(net "M_A_CPU0_SB_DQ<6>")
	)
	(segment
		(start 318.467994 -226.288854)
		(end 318.274954 -226.095814)
		(width 0.18288)
		(layer "In2.Cu")
		(net "M_A_CPU0_SB_DQ<6>")
	)
	(segment
		(start 316.156594 -225.630232)
		(end 316.156594 -226.095814)
		(width 0.18288)
		(layer "In2.Cu")
		(net "M_A_CPU0_SB_DQ<6>")
	)
	(segment
		(start 336.272378 -236.108494)
		(end 336.258916 -236.116114)
		(width 0.088646)
		(layer "In2.Cu")
		(net "M_A_CPU0_SB_DQ<6>")
	)
	(segment
		(start 315.963554 -226.288854)
		(end 315.619638 -226.288854)
		(width 0.18288)
		(layer "In2.Cu")
		(net "M_A_CPU0_SB_DQ<6>")
	)
	(segment
		(start 318.274954 -226.095814)
		(end 318.274954 -225.617024)
		(width 0.18288)
		(layer "In2.Cu")
		(net "M_A_CPU0_SB_DQ<6>")
	)
	(segment
		(start 316.156594 -226.095814)
		(end 315.963554 -226.288854)
		(width 0.18288)
		(layer "In2.Cu")
		(net "M_A_CPU0_SB_DQ<6>")
	)
	(segment
		(start 338.43468 -236.597952)
		(end 338.122006 -236.597952)
		(width 0.088646)
		(layer "In2.Cu")
		(net "M_A_CPU0_SB_DQ<6>")
	)
	(segment
		(start 317.055754 -226.288854)
		(end 316.862714 -226.095814)
		(width 0.18288)
		(layer "In2.Cu")
		(net "M_A_CPU0_SB_DQ<6>")
	)
	(segment
		(start 318.081914 -225.423984)
		(end 317.761874 -225.423984)
		(width 0.18288)
		(layer "In2.Cu")
		(net "M_A_CPU0_SB_DQ<6>")
	)
	(segment
		(start 332.031594 -236.09808)
		(end 331.701648 -236.09808)
		(width 0.088646)
		(layer "In2.Cu")
		(net "M_A_CPU0_SB_DQ<6>")
	)
	(segment
		(start 317.568834 -226.095814)
		(end 317.375794 -226.288854)
		(width 0.18288)
		(layer "In2.Cu")
		(net "M_A_CPU0_SB_DQ<6>")
	)
	(segment
		(start 317.568834 -225.617024)
		(end 317.568834 -226.095814)
		(width 0.18288)
		(layer "In2.Cu")
		(net "M_A_CPU0_SB_DQ<6>")
	)
	(segment
		(start 316.669674 -225.437192)
		(end 316.349634 -225.437192)
		(width 0.18288)
		(layer "In2.Cu")
		(net "M_A_CPU0_SB_DQ<6>")
	)
	(segment
		(start 315.233558 -225.36658)
		(end 314.092082 -225.36658)
		(width 0.18288)
		(layer "In2.Cu")
		(net "M_A_CPU0_SB_DQ<6>")
	)
	(segment
		(start 338.122006 -236.597952)
		(end 338.056474 -236.53242)
		(width 0.088646)
		(layer "In2.Cu")
		(net "M_A_CPU0_SB_DQ<6>")
	)
	(segment
		(start 331.701648 -236.09808)
		(end 331.57795 -236.221778)
		(width 0.088646)
		(layer "In2.Cu")
		(net "M_A_CPU0_SB_DQ<6>")
	)
	(segment
		(start 328.999088 -236.221778)
		(end 319.066164 -226.288854)
		(width 0.18288)
		(layer "In2.Cu")
		(net "M_A_CPU0_SB_DQ<6>")
	)
	(segment
		(start 333.452978 -236.10824)
		(end 333.453232 -236.10824)
		(width 0.088646)
		(layer "In2.Cu")
		(net "M_A_CPU0_SB_DQ<6>")
	)
	(segment
		(start 335.915 -236.117892)
		(end 335.897982 -236.10824)
		(width 0.088646)
		(layer "In2.Cu")
		(net "M_A_CPU0_SB_DQ<6>")
	)
	(segment
		(start 315.619638 -226.288854)
		(end 315.426598 -226.095814)
		(width 0.18288)
		(layer "In2.Cu")
		(net "M_A_CPU0_SB_DQ<6>")
	)
	(segment
		(start 316.862714 -225.630232)
		(end 316.669674 -225.437192)
		(width 0.18288)
		(layer "In2.Cu")
		(net "M_A_CPU0_SB_DQ<6>")
	)
	(segment
		(start 315.426598 -225.55962)
		(end 315.233558 -225.36658)
		(width 0.18288)
		(layer "In2.Cu")
		(net "M_A_CPU0_SB_DQ<6>")
	)
	(segment
		(start 318.274954 -225.617024)
		(end 318.081914 -225.423984)
		(width 0.18288)
		(layer "In2.Cu")
		(net "M_A_CPU0_SB_DQ<6>")
	)
	(segment
		(start 316.349634 -225.437192)
		(end 316.156594 -225.630232)
		(width 0.18288)
		(layer "In2.Cu")
		(net "M_A_CPU0_SB_DQ<6>")
	)
	(arc
		(start 332.513432 -236.10824)
		(mid 332.348552 -236.157718)
		(end 332.178914 -236.128306)
		(width 0.088646)
		(layer "In2.Cu")
		(net "M_A_CPU0_SB_DQ<6>")
	)
	(arc
		(start 337.212178 -236.108494)
		(mid 337.02498 -236.158637)
		(end 336.837782 -236.108494)
		(width 0.088646)
		(layer "In2.Cu")
		(net "M_A_CPU0_SB_DQ<6>")
	)
	(arc
		(start 333.453232 -236.10824)
		(mid 333.266034 -236.158383)
		(end 333.078836 -236.10824)
		(width 0.088646)
		(layer "In2.Cu")
		(net "M_A_CPU0_SB_DQ<6>")
	)
	(arc
		(start 332.178914 -236.128306)
		(mid 332.106786 -236.10573)
		(end 332.031594 -236.09808)
		(width 0.088646)
		(layer "In2.Cu")
		(net "M_A_CPU0_SB_DQ<6>")
	)
	(arc
		(start 336.258916 -236.116114)
		(mid 336.087198 -236.162526)
		(end 335.915 -236.117892)
		(width 0.088646)
		(layer "In2.Cu")
		(net "M_A_CPU0_SB_DQ<6>")
	)
	(arc
		(start 333.078836 -236.10824)
		(mid 332.796134 -236.032498)
		(end 332.513432 -236.10824)
		(width 0.088646)
		(layer "In2.Cu")
		(net "M_A_CPU0_SB_DQ<6>")
	)
	(arc
		(start 334.018382 -236.10824)
		(mid 333.73568 -236.032464)
		(end 333.452978 -236.10824)
		(width 0.088646)
		(layer "In2.Cu")
		(net "M_A_CPU0_SB_DQ<6>")
	)
	(arc
		(start 336.837782 -236.108494)
		(mid 336.55508 -236.032718)
		(end 336.272378 -236.108494)
		(width 0.088646)
		(layer "In2.Cu")
		(net "M_A_CPU0_SB_DQ<6>")
	)
	(arc
		(start 334.958182 -236.10824)
		(mid 334.67548 -236.032464)
		(end 334.392778 -236.10824)
		(width 0.088646)
		(layer "In2.Cu")
		(net "M_A_CPU0_SB_DQ<6>")
	)
	(arc
		(start 335.897982 -236.10824)
		(mid 335.61528 -236.032464)
		(end 335.332578 -236.10824)
		(width 0.088646)
		(layer "In2.Cu")
		(net "M_A_CPU0_SB_DQ<6>")
	)
	(arc
		(start 338.056474 -236.53242)
		(mid 337.748638 -236.09269)
		(end 337.212178 -236.108494)
		(width 0.088646)
		(layer "In2.Cu")
		(net "M_A_CPU0_SB_DQ<6>")
	)
	(arc
		(start 334.392778 -236.10824)
		(mid 334.20558 -236.158383)
		(end 334.018382 -236.10824)
		(width 0.088646)
		(layer "In2.Cu")
		(net "M_A_CPU0_SB_DQ<6>")
	)
	(arc
		(start 335.332578 -236.10824)
		(mid 335.14538 -236.158383)
		(end 334.958182 -236.10824)
		(width 0.088646)
		(layer "In2.Cu")
		(net "M_A_CPU0_SB_DQ<6>")
	)
	(segment
		(start 302.87976 -224.74301)
		(end 302.653446 -224.516696)
		(width 0.20066)
		(layer "F.Cu")
		(net "M_A_CPU0_SB_DQ<5>")
	)
	(segment
		(start 303.523396 -224.246186)
		(end 303.523396 -224.56775)
		(width 0.20066)
		(layer "F.Cu")
		(net "M_A_CPU0_SB_DQ<5>")
	)
	(segment
		(start 337.025234 -236.319568)
		(end 337.025234 -235.783882)
		(width 0.20066)
		(layer "F.Cu")
		(net "M_A_CPU0_SB_DQ<5>")
	)
	(segment
		(start 304.550826 -224.0915)
		(end 304.325528 -224.0915)
		(width 0.101854)
		(layer "F.Cu")
		(net "M_A_CPU0_SB_DQ<5>")
	)
	(segment
		(start 306.289202 -224.0915)
		(end 304.550826 -224.0915)
		(width 0.1016)
		(layer "F.Cu")
		(net "M_A_CPU0_SB_DQ<5>")
	)
	(segment
		(start 309.992014 -224.516696)
		(end 308.887114 -224.516696)
		(width 0.20066)
		(layer "F.Cu")
		(net "M_A_CPU0_SB_DQ<5>")
	)
	(segment
		(start 337.02498 -236.319822)
		(end 337.025234 -236.319568)
		(width 0.20066)
		(layer "F.Cu")
		(net "M_A_CPU0_SB_DQ<5>")
	)
	(segment
		(start 306.797964 -224.0915)
		(end 306.644294 -224.0915)
		(width 0.20066)
		(layer "F.Cu")
		(net "M_A_CPU0_SB_DQ<5>")
	)
	(segment
		(start 308.887114 -224.516696)
		(end 307.22316 -224.516696)
		(width 0.20066)
		(layer "F.Cu")
		(net "M_A_CPU0_SB_DQ<5>")
	)
	(segment
		(start 303.348136 -224.74301)
		(end 302.87976 -224.74301)
		(width 0.20066)
		(layer "F.Cu")
		(net "M_A_CPU0_SB_DQ<5>")
	)
	(segment
		(start 303.684432 -224.08515)
		(end 303.523396 -224.246186)
		(width 0.20066)
		(layer "F.Cu")
		(net "M_A_CPU0_SB_DQ<5>")
	)
	(segment
		(start 303.523396 -224.56775)
		(end 303.348136 -224.74301)
		(width 0.20066)
		(layer "F.Cu")
		(net "M_A_CPU0_SB_DQ<5>")
	)
	(segment
		(start 307.22316 -224.516696)
		(end 306.797964 -224.0915)
		(width 0.20066)
		(layer "F.Cu")
		(net "M_A_CPU0_SB_DQ<5>")
	)
	(segment
		(start 306.644294 -224.0915)
		(end 306.289202 -224.0915)
		(width 0.101854)
		(layer "F.Cu")
		(net "M_A_CPU0_SB_DQ<5>")
	)
	(segment
		(start 302.653446 -224.516696)
		(end 301.343314 -224.516696)
		(width 0.20066)
		(layer "F.Cu")
		(net "M_A_CPU0_SB_DQ<5>")
	)
	(segment
		(start 304.325528 -224.0915)
		(end 304.319178 -224.08515)
		(width 0.101854)
		(layer "F.Cu")
		(net "M_A_CPU0_SB_DQ<5>")
	)
	(segment
		(start 304.319178 -224.08515)
		(end 303.684432 -224.08515)
		(width 0.20066)
		(layer "F.Cu")
		(net "M_A_CPU0_SB_DQ<5>")
	)
	(segment
		(start 314.37707 -224.841054)
		(end 314.276486 -224.941638)
		(width 0.18288)
		(layer "In2.Cu")
		(net "M_A_CPU0_SB_DQ<5>")
	)
	(segment
		(start 337.337908 -235.783882)
		(end 337.395058 -235.726732)
		(width 0.088646)
		(layer "In2.Cu")
		(net "M_A_CPU0_SB_DQ<5>")
	)
	(segment
		(start 337.221068 -235.464604)
		(end 337.218528 -235.46308)
		(width 0.088646)
		(layer "In2.Cu")
		(net "M_A_CPU0_SB_DQ<5>")
	)
	(segment
		(start 334.407764 -235.46816)
		(end 334.393032 -235.459524)
		(width 0.088646)
		(layer "In2.Cu")
		(net "M_A_CPU0_SB_DQ<5>")
	)
	(segment
		(start 330.699364 -235.876338)
		(end 329.382628 -235.876338)
		(width 0.18288)
		(layer "In2.Cu")
		(net "M_A_CPU0_SB_DQ<5>")
	)
	(segment
		(start 337.218528 -235.46308)
		(end 337.212432 -235.459524)
		(width 0.088646)
		(layer "In2.Cu")
		(net "M_A_CPU0_SB_DQ<5>")
	)
	(segment
		(start 314.276486 -224.941638)
		(end 312.142886 -224.941638)
		(width 0.18288)
		(layer "In2.Cu")
		(net "M_A_CPU0_SB_DQ<5>")
	)
	(segment
		(start 318.347344 -224.841054)
		(end 314.37707 -224.841054)
		(width 0.18288)
		(layer "In2.Cu")
		(net "M_A_CPU0_SB_DQ<5>")
	)
	(segment
		(start 333.467964 -235.46816)
		(end 333.453232 -235.459524)
		(width 0.088646)
		(layer "In2.Cu")
		(net "M_A_CPU0_SB_DQ<5>")
	)
	(segment
		(start 332.061058 -235.518706)
		(end 331.85354 -235.726224)
		(width 0.088646)
		(layer "In2.Cu")
		(net "M_A_CPU0_SB_DQ<5>")
	)
	(segment
		(start 311.92216 -225.162364)
		(end 310.637682 -225.162364)
		(width 0.18288)
		(layer "In2.Cu")
		(net "M_A_CPU0_SB_DQ<5>")
	)
	(segment
		(start 337.025234 -235.783882)
		(end 337.337908 -235.783882)
		(width 0.088646)
		(layer "In2.Cu")
		(net "M_A_CPU0_SB_DQ<5>")
	)
	(segment
		(start 331.616304 -235.726224)
		(end 331.46619 -235.876338)
		(width 0.088646)
		(layer "In2.Cu")
		(net "M_A_CPU0_SB_DQ<5>")
	)
	(segment
		(start 312.142886 -224.941638)
		(end 311.92216 -225.162364)
		(width 0.18288)
		(layer "In2.Cu")
		(net "M_A_CPU0_SB_DQ<5>")
	)
	(segment
		(start 332.528164 -235.46816)
		(end 332.513432 -235.459524)
		(width 0.088646)
		(layer "In2.Cu")
		(net "M_A_CPU0_SB_DQ<5>")
	)
	(segment
		(start 335.347564 -235.46816)
		(end 335.332832 -235.459524)
		(width 0.088646)
		(layer "In2.Cu")
		(net "M_A_CPU0_SB_DQ<5>")
	)
	(segment
		(start 329.382628 -235.876338)
		(end 318.347344 -224.841054)
		(width 0.18288)
		(layer "In2.Cu")
		(net "M_A_CPU0_SB_DQ<5>")
	)
	(segment
		(start 310.637682 -225.162364)
		(end 309.992014 -224.516696)
		(width 0.18288)
		(layer "In2.Cu")
		(net "M_A_CPU0_SB_DQ<5>")
	)
	(segment
		(start 336.287364 -235.46816)
		(end 336.272632 -235.459524)
		(width 0.088646)
		(layer "In2.Cu")
		(net "M_A_CPU0_SB_DQ<5>")
	)
	(segment
		(start 331.46619 -235.876338)
		(end 330.699364 -235.876338)
		(width 0.088646)
		(layer "In2.Cu")
		(net "M_A_CPU0_SB_DQ<5>")
	)
	(segment
		(start 331.85354 -235.726224)
		(end 331.616304 -235.726224)
		(width 0.088646)
		(layer "In2.Cu")
		(net "M_A_CPU0_SB_DQ<5>")
	)
	(arc
		(start 336.272632 -235.459524)
		(mid 336.085434 -235.409381)
		(end 335.898236 -235.459524)
		(width 0.088646)
		(layer "In2.Cu")
		(net "M_A_CPU0_SB_DQ<5>")
	)
	(arc
		(start 332.513432 -235.459524)
		(mid 332.326234 -235.409381)
		(end 332.139036 -235.459524)
		(width 0.088646)
		(layer "In2.Cu")
		(net "M_A_CPU0_SB_DQ<5>")
	)
	(arc
		(start 334.393032 -235.459524)
		(mid 334.205834 -235.409381)
		(end 334.018636 -235.459524)
		(width 0.088646)
		(layer "In2.Cu")
		(net "M_A_CPU0_SB_DQ<5>")
	)
	(arc
		(start 337.395058 -235.726732)
		(mid 337.336939 -235.576491)
		(end 337.221068 -235.464604)
		(width 0.088646)
		(layer "In2.Cu")
		(net "M_A_CPU0_SB_DQ<5>")
	)
	(arc
		(start 334.958436 -235.459524)
		(mid 334.684237 -235.535359)
		(end 334.407764 -235.46816)
		(width 0.088646)
		(layer "In2.Cu")
		(net "M_A_CPU0_SB_DQ<5>")
	)
	(arc
		(start 335.332832 -235.459524)
		(mid 335.145634 -235.409381)
		(end 334.958436 -235.459524)
		(width 0.088646)
		(layer "In2.Cu")
		(net "M_A_CPU0_SB_DQ<5>")
	)
	(arc
		(start 333.078836 -235.459524)
		(mid 332.804637 -235.535359)
		(end 332.528164 -235.46816)
		(width 0.088646)
		(layer "In2.Cu")
		(net "M_A_CPU0_SB_DQ<5>")
	)
	(arc
		(start 332.139036 -235.459524)
		(mid 332.098106 -235.486557)
		(end 332.061058 -235.518706)
		(width 0.088646)
		(layer "In2.Cu")
		(net "M_A_CPU0_SB_DQ<5>")
	)
	(arc
		(start 337.212432 -235.459524)
		(mid 337.025234 -235.409381)
		(end 336.838036 -235.459524)
		(width 0.088646)
		(layer "In2.Cu")
		(net "M_A_CPU0_SB_DQ<5>")
	)
	(arc
		(start 336.838036 -235.459524)
		(mid 336.563837 -235.535359)
		(end 336.287364 -235.46816)
		(width 0.088646)
		(layer "In2.Cu")
		(net "M_A_CPU0_SB_DQ<5>")
	)
	(arc
		(start 335.898236 -235.459524)
		(mid 335.624037 -235.535359)
		(end 335.347564 -235.46816)
		(width 0.088646)
		(layer "In2.Cu")
		(net "M_A_CPU0_SB_DQ<5>")
	)
	(arc
		(start 334.018636 -235.459524)
		(mid 333.744437 -235.535359)
		(end 333.467964 -235.46816)
		(width 0.088646)
		(layer "In2.Cu")
		(net "M_A_CPU0_SB_DQ<5>")
	)
	(arc
		(start 333.453232 -235.459524)
		(mid 333.266034 -235.409381)
		(end 333.078836 -235.459524)
		(width 0.088646)
		(layer "In2.Cu")
		(net "M_A_CPU0_SB_DQ<5>")
	)
	(segment
		(start 309.992014 -226.216718)
		(end 308.887114 -226.216718)
		(width 0.20066)
		(layer "F.Cu")
		(net "M_A_CPU0_SB_DQ<4>")
	)
	(segment
		(start 306.27066 -225.791522)
		(end 304.550826 -225.791522)
		(width 0.1016)
		(layer "F.Cu")
		(net "M_A_CPU0_SB_DQ<4>")
	)
	(segment
		(start 306.847748 -225.791522)
		(end 306.644294 -225.791522)
		(width 0.20066)
		(layer "F.Cu")
		(net "M_A_CPU0_SB_DQ<4>")
	)
	(segment
		(start 302.90516 -226.468432)
		(end 302.653446 -226.216718)
		(width 0.20066)
		(layer "F.Cu")
		(net "M_A_CPU0_SB_DQ<4>")
	)
	(segment
		(start 302.653446 -226.216718)
		(end 301.343314 -226.216718)
		(width 0.20066)
		(layer "F.Cu")
		(net "M_A_CPU0_SB_DQ<4>")
	)
	(segment
		(start 303.68367 -225.785934)
		(end 303.523396 -225.946208)
		(width 0.20066)
		(layer "F.Cu")
		(net "M_A_CPU0_SB_DQ<4>")
	)
	(segment
		(start 303.523396 -226.234244)
		(end 303.289208 -226.468432)
		(width 0.20066)
		(layer "F.Cu")
		(net "M_A_CPU0_SB_DQ<4>")
	)
	(segment
		(start 336.555334 -237.133892)
		(end 336.555334 -236.597952)
		(width 0.20066)
		(layer "F.Cu")
		(net "M_A_CPU0_SB_DQ<4>")
	)
	(segment
		(start 304.324766 -225.791522)
		(end 304.319178 -225.785934)
		(width 0.101854)
		(layer "F.Cu")
		(net "M_A_CPU0_SB_DQ<4>")
	)
	(segment
		(start 303.289208 -226.468432)
		(end 302.90516 -226.468432)
		(width 0.20066)
		(layer "F.Cu")
		(net "M_A_CPU0_SB_DQ<4>")
	)
	(segment
		(start 307.272944 -226.216718)
		(end 306.847748 -225.791522)
		(width 0.20066)
		(layer "F.Cu")
		(net "M_A_CPU0_SB_DQ<4>")
	)
	(segment
		(start 303.523396 -225.946208)
		(end 303.523396 -226.234244)
		(width 0.20066)
		(layer "F.Cu")
		(net "M_A_CPU0_SB_DQ<4>")
	)
	(segment
		(start 304.319178 -225.785934)
		(end 303.68367 -225.785934)
		(width 0.20066)
		(layer "F.Cu")
		(net "M_A_CPU0_SB_DQ<4>")
	)
	(segment
		(start 304.550826 -225.791522)
		(end 304.324766 -225.791522)
		(width 0.101854)
		(layer "F.Cu")
		(net "M_A_CPU0_SB_DQ<4>")
	)
	(segment
		(start 306.644294 -225.791522)
		(end 306.27066 -225.791522)
		(width 0.101854)
		(layer "F.Cu")
		(net "M_A_CPU0_SB_DQ<4>")
	)
	(segment
		(start 308.887114 -226.216718)
		(end 307.272944 -226.216718)
		(width 0.20066)
		(layer "F.Cu")
		(net "M_A_CPU0_SB_DQ<4>")
	)
	(segment
		(start 318.862202 -226.809808)
		(end 315.32957 -226.809808)
		(width 0.18288)
		(layer "In2.Cu")
		(net "M_A_CPU0_SB_DQ<4>")
	)
	(segment
		(start 328.619612 -236.567218)
		(end 318.862202 -226.809808)
		(width 0.18288)
		(layer "In2.Cu")
		(net "M_A_CPU0_SB_DQ<4>")
	)
	(segment
		(start 314.313316 -225.793554)
		(end 312.093102 -225.793554)
		(width 0.18288)
		(layer "In2.Cu")
		(net "M_A_CPU0_SB_DQ<4>")
	)
	(segment
		(start 330.699364 -236.567218)
		(end 328.619612 -236.567218)
		(width 0.18288)
		(layer "In2.Cu")
		(net "M_A_CPU0_SB_DQ<4>")
	)
	(segment
		(start 310.384698 -226.609402)
		(end 309.992014 -226.216718)
		(width 0.18288)
		(layer "In2.Cu")
		(net "M_A_CPU0_SB_DQ<4>")
	)
	(segment
		(start 312.093102 -225.793554)
		(end 311.989978 -225.69043)
		(width 0.18288)
		(layer "In2.Cu")
		(net "M_A_CPU0_SB_DQ<4>")
	)
	(segment
		(start 331.537564 -236.567218)
		(end 330.699364 -236.567218)
		(width 0.088646)
		(layer "In2.Cu")
		(net "M_A_CPU0_SB_DQ<4>")
	)
	(segment
		(start 333.548482 -236.27334)
		(end 333.548736 -236.273594)
		(width 0.088646)
		(layer "In2.Cu")
		(net "M_A_CPU0_SB_DQ<4>")
	)
	(segment
		(start 315.32957 -226.809808)
		(end 314.313316 -225.793554)
		(width 0.18288)
		(layer "In2.Cu")
		(net "M_A_CPU0_SB_DQ<4>")
	)
	(segment
		(start 336.555334 -236.597952)
		(end 336.04073 -236.412024)
		(width 0.088646)
		(layer "In2.Cu")
		(net "M_A_CPU0_SB_DQ<4>")
	)
	(segment
		(start 310.611012 -226.609402)
		(end 310.384698 -226.609402)
		(width 0.18288)
		(layer "In2.Cu")
		(net "M_A_CPU0_SB_DQ<4>")
	)
	(segment
		(start 331.803502 -236.30128)
		(end 331.537564 -236.567218)
		(width 0.088646)
		(layer "In2.Cu")
		(net "M_A_CPU0_SB_DQ<4>")
	)
	(segment
		(start 311.529984 -225.69043)
		(end 310.611012 -226.609402)
		(width 0.18288)
		(layer "In2.Cu")
		(net "M_A_CPU0_SB_DQ<4>")
	)
	(segment
		(start 311.989978 -225.69043)
		(end 311.529984 -225.69043)
		(width 0.18288)
		(layer "In2.Cu")
		(net "M_A_CPU0_SB_DQ<4>")
	)
	(segment
		(start 336.04073 -236.412024)
		(end 335.802478 -236.27334)
		(width 0.088646)
		(layer "In2.Cu")
		(net "M_A_CPU0_SB_DQ<4>")
	)
	(segment
		(start 331.999844 -236.30128)
		(end 331.803502 -236.30128)
		(width 0.088646)
		(layer "In2.Cu")
		(net "M_A_CPU0_SB_DQ<4>")
	)
	(arc
		(start 334.488282 -236.27334)
		(mid 334.20558 -236.349116)
		(end 333.922878 -236.27334)
		(width 0.088646)
		(layer "In2.Cu")
		(net "M_A_CPU0_SB_DQ<4>")
	)
	(arc
		(start 333.548736 -236.273594)
		(mid 333.266034 -236.349336)
		(end 332.983332 -236.273594)
		(width 0.088646)
		(layer "In2.Cu")
		(net "M_A_CPU0_SB_DQ<4>")
	)
	(arc
		(start 333.922878 -236.27334)
		(mid 333.73568 -236.223197)
		(end 333.548482 -236.27334)
		(width 0.088646)
		(layer "In2.Cu")
		(net "M_A_CPU0_SB_DQ<4>")
	)
	(arc
		(start 335.802478 -236.27334)
		(mid 335.61528 -236.223197)
		(end 335.428082 -236.27334)
		(width 0.088646)
		(layer "In2.Cu")
		(net "M_A_CPU0_SB_DQ<4>")
	)
	(arc
		(start 332.608936 -236.273594)
		(mid 332.391285 -236.34568)
		(end 332.162912 -236.32541)
		(width 0.088646)
		(layer "In2.Cu")
		(net "M_A_CPU0_SB_DQ<4>")
	)
	(arc
		(start 332.983332 -236.273594)
		(mid 332.796134 -236.223451)
		(end 332.608936 -236.273594)
		(width 0.088646)
		(layer "In2.Cu")
		(net "M_A_CPU0_SB_DQ<4>")
	)
	(arc
		(start 334.862678 -236.27334)
		(mid 334.67548 -236.223197)
		(end 334.488282 -236.27334)
		(width 0.088646)
		(layer "In2.Cu")
		(net "M_A_CPU0_SB_DQ<4>")
	)
	(arc
		(start 332.162912 -236.32541)
		(mid 332.082261 -236.307383)
		(end 331.999844 -236.30128)
		(width 0.088646)
		(layer "In2.Cu")
		(net "M_A_CPU0_SB_DQ<4>")
	)
	(arc
		(start 335.428082 -236.27334)
		(mid 335.14538 -236.349082)
		(end 334.862678 -236.27334)
		(width 0.088646)
		(layer "In2.Cu")
		(net "M_A_CPU0_SB_DQ<4>")
	)
	(segment
		(start 338.434934 -238.761524)
		(end 338.43468 -238.225584)
		(width 0.20066)
		(layer "F.Cu")
		(net "M_A_CPU0_SB_DQ<3>")
	)
	(segment
		(start 307.051964 -229.616762)
		(end 305.443382 -229.616762)
		(width 0.20066)
		(layer "F.Cu")
		(net "M_A_CPU0_SB_DQ<3>")
	)
	(segment
		(start 314.092082 -229.616762)
		(end 312.987182 -229.616762)
		(width 0.20066)
		(layer "F.Cu")
		(net "M_A_CPU0_SB_DQ<3>")
	)
	(segment
		(start 310.01208 -230.041704)
		(end 307.85308 -230.041704)
		(width 0.1016)
		(layer "F.Cu")
		(net "M_A_CPU0_SB_DQ<3>")
	)
	(segment
		(start 307.76291 -230.062024)
		(end 307.497226 -230.062024)
		(width 0.20066)
		(layer "F.Cu")
		(net "M_A_CPU0_SB_DQ<3>")
	)
	(segment
		(start 307.85308 -230.041704)
		(end 307.81371 -230.041704)
		(width 0.101854)
		(layer "F.Cu")
		(net "M_A_CPU0_SB_DQ<3>")
	)
	(segment
		(start 310.775858 -229.39502)
		(end 310.609996 -229.560882)
		(width 0.20066)
		(layer "F.Cu")
		(net "M_A_CPU0_SB_DQ<3>")
	)
	(segment
		(start 312.987182 -229.616762)
		(end 311.491122 -229.616762)
		(width 0.20066)
		(layer "F.Cu")
		(net "M_A_CPU0_SB_DQ<3>")
	)
	(segment
		(start 307.81371 -230.041704)
		(end 307.79339 -230.062024)
		(width 0.101854)
		(layer "F.Cu")
		(net "M_A_CPU0_SB_DQ<3>")
	)
	(segment
		(start 307.497226 -230.062024)
		(end 307.051964 -229.616762)
		(width 0.20066)
		(layer "F.Cu")
		(net "M_A_CPU0_SB_DQ<3>")
	)
	(segment
		(start 310.609996 -229.91445)
		(end 310.482742 -230.041704)
		(width 0.20066)
		(layer "F.Cu")
		(net "M_A_CPU0_SB_DQ<3>")
	)
	(segment
		(start 311.491122 -229.616762)
		(end 311.26938 -229.39502)
		(width 0.20066)
		(layer "F.Cu")
		(net "M_A_CPU0_SB_DQ<3>")
	)
	(segment
		(start 310.609996 -229.560882)
		(end 310.609996 -229.91445)
		(width 0.20066)
		(layer "F.Cu")
		(net "M_A_CPU0_SB_DQ<3>")
	)
	(segment
		(start 310.088026 -230.041704)
		(end 310.01208 -230.041704)
		(width 0.101854)
		(layer "F.Cu")
		(net "M_A_CPU0_SB_DQ<3>")
	)
	(segment
		(start 311.26938 -229.39502)
		(end 310.775858 -229.39502)
		(width 0.20066)
		(layer "F.Cu")
		(net "M_A_CPU0_SB_DQ<3>")
	)
	(segment
		(start 307.79339 -230.062024)
		(end 307.76291 -230.062024)
		(width 0.101854)
		(layer "F.Cu")
		(net "M_A_CPU0_SB_DQ<3>")
	)
	(segment
		(start 310.482742 -230.041704)
		(end 310.088026 -230.041704)
		(width 0.20066)
		(layer "F.Cu")
		(net "M_A_CPU0_SB_DQ<3>")
	)
	(segment
		(start 338.43468 -238.225584)
		(end 338.434426 -238.225838)
		(width 0.088646)
		(layer "In2.Cu")
		(net "M_A_CPU0_SB_DQ<3>")
	)
	(segment
		(start 315.721238 -230.50754)
		(end 315.721238 -229.809802)
		(width 0.18288)
		(layer "In2.Cu")
		(net "M_A_CPU0_SB_DQ<3>")
	)
	(segment
		(start 316.726062 -229.649274)
		(end 316.522862 -229.852474)
		(width 0.18288)
		(layer "In2.Cu")
		(net "M_A_CPU0_SB_DQ<3>")
	)
	(segment
		(start 316.522862 -230.50754)
		(end 316.329822 -230.70058)
		(width 0.18288)
		(layer "In2.Cu")
		(net "M_A_CPU0_SB_DQ<3>")
	)
	(segment
		(start 338.434426 -238.225838)
		(end 338.057236 -238.225838)
		(width 0.088646)
		(layer "In2.Cu")
		(net "M_A_CPU0_SB_DQ<3>")
	)
	(segment
		(start 318.940688 -230.769414)
		(end 318.747648 -230.576374)
		(width 0.18288)
		(layer "In2.Cu")
		(net "M_A_CPU0_SB_DQ<3>")
	)
	(segment
		(start 331.856334 -238.600488)
		(end 331.562456 -238.600488)
		(width 0.088646)
		(layer "In2.Cu")
		(net "M_A_CPU0_SB_DQ<3>")
	)
	(segment
		(start 317.99911 -230.576374)
		(end 317.80607 -230.769414)
		(width 0.18288)
		(layer "In2.Cu")
		(net "M_A_CPU0_SB_DQ<3>")
	)
	(segment
		(start 338.034884 -238.216694)
		(end 337.782154 -237.963964)
		(width 0.088646)
		(layer "In2.Cu")
		(net "M_A_CPU0_SB_DQ<3>")
	)
	(segment
		(start 331.562456 -238.600488)
		(end 331.206348 -238.24438)
		(width 0.088646)
		(layer "In2.Cu")
		(net "M_A_CPU0_SB_DQ<3>")
	)
	(segment
		(start 336.368136 -237.901226)
		(end 336.367882 -237.901226)
		(width 0.088646)
		(layer "In2.Cu")
		(net "M_A_CPU0_SB_DQ<3>")
	)
	(segment
		(start 316.329822 -230.70058)
		(end 315.914278 -230.70058)
		(width 0.18288)
		(layer "In2.Cu")
		(net "M_A_CPU0_SB_DQ<3>")
	)
	(segment
		(start 315.721238 -229.809802)
		(end 315.528198 -229.616762)
		(width 0.18288)
		(layer "In2.Cu")
		(net "M_A_CPU0_SB_DQ<3>")
	)
	(segment
		(start 330.699364 -238.24438)
		(end 327.048622 -238.24438)
		(width 0.18288)
		(layer "In2.Cu")
		(net "M_A_CPU0_SB_DQ<3>")
	)
	(segment
		(start 317.295784 -229.845108)
		(end 317.09995 -229.649274)
		(width 0.18288)
		(layer "In2.Cu")
		(net "M_A_CPU0_SB_DQ<3>")
	)
	(segment
		(start 318.19215 -229.802944)
		(end 317.99911 -229.995984)
		(width 0.18288)
		(layer "In2.Cu")
		(net "M_A_CPU0_SB_DQ<3>")
	)
	(segment
		(start 336.18932 -238.145574)
		(end 335.958942 -238.374936)
		(width 0.088646)
		(layer "In2.Cu")
		(net "M_A_CPU0_SB_DQ<3>")
	)
	(segment
		(start 319.573656 -230.769414)
		(end 318.940688 -230.769414)
		(width 0.18288)
		(layer "In2.Cu")
		(net "M_A_CPU0_SB_DQ<3>")
	)
	(segment
		(start 318.747648 -230.576374)
		(end 318.747648 -230.038402)
		(width 0.18288)
		(layer "In2.Cu")
		(net "M_A_CPU0_SB_DQ<3>")
	)
	(segment
		(start 317.99911 -229.995984)
		(end 317.99911 -230.576374)
		(width 0.18288)
		(layer "In2.Cu")
		(net "M_A_CPU0_SB_DQ<3>")
	)
	(segment
		(start 318.51219 -229.802944)
		(end 318.19215 -229.802944)
		(width 0.18288)
		(layer "In2.Cu")
		(net "M_A_CPU0_SB_DQ<3>")
	)
	(segment
		(start 316.522862 -229.852474)
		(end 316.522862 -230.50754)
		(width 0.18288)
		(layer "In2.Cu")
		(net "M_A_CPU0_SB_DQ<3>")
	)
	(segment
		(start 317.09995 -229.649274)
		(end 316.726062 -229.649274)
		(width 0.18288)
		(layer "In2.Cu")
		(net "M_A_CPU0_SB_DQ<3>")
	)
	(segment
		(start 317.488824 -230.769414)
		(end 317.295784 -230.576374)
		(width 0.18288)
		(layer "In2.Cu")
		(net "M_A_CPU0_SB_DQ<3>")
	)
	(segment
		(start 327.048622 -238.24438)
		(end 319.573656 -230.769414)
		(width 0.18288)
		(layer "In2.Cu")
		(net "M_A_CPU0_SB_DQ<3>")
	)
	(segment
		(start 317.80607 -230.769414)
		(end 317.488824 -230.769414)
		(width 0.18288)
		(layer "In2.Cu")
		(net "M_A_CPU0_SB_DQ<3>")
	)
	(segment
		(start 317.295784 -230.576374)
		(end 317.295784 -229.845108)
		(width 0.18288)
		(layer "In2.Cu")
		(net "M_A_CPU0_SB_DQ<3>")
	)
	(segment
		(start 318.747648 -230.038402)
		(end 318.51219 -229.802944)
		(width 0.18288)
		(layer "In2.Cu")
		(net "M_A_CPU0_SB_DQ<3>")
	)
	(segment
		(start 315.914278 -230.70058)
		(end 315.721238 -230.50754)
		(width 0.18288)
		(layer "In2.Cu")
		(net "M_A_CPU0_SB_DQ<3>")
	)
	(segment
		(start 315.528198 -229.616762)
		(end 314.092082 -229.616762)
		(width 0.18288)
		(layer "In2.Cu")
		(net "M_A_CPU0_SB_DQ<3>")
	)
	(segment
		(start 331.206348 -238.24438)
		(end 330.699364 -238.24438)
		(width 0.088646)
		(layer "In2.Cu")
		(net "M_A_CPU0_SB_DQ<3>")
	)
	(arc
		(start 338.057236 -238.225838)
		(mid 338.045183 -238.223441)
		(end 338.034884 -238.216694)
		(width 0.088646)
		(layer "In2.Cu")
		(net "M_A_CPU0_SB_DQ<3>")
	)
	(arc
		(start 337.782154 -237.963964)
		(mid 337.555531 -237.852293)
		(end 337.307682 -237.90148)
		(width 0.088646)
		(layer "In2.Cu")
		(net "M_A_CPU0_SB_DQ<3>")
	)
	(arc
		(start 332.608936 -238.549942)
		(mid 332.326234 -238.474166)
		(end 332.043532 -238.549942)
		(width 0.088646)
		(layer "In2.Cu")
		(net "M_A_CPU0_SB_DQ<3>")
	)
	(arc
		(start 335.802732 -238.549942)
		(mid 335.615534 -238.600085)
		(end 335.428336 -238.549942)
		(width 0.088646)
		(layer "In2.Cu")
		(net "M_A_CPU0_SB_DQ<3>")
	)
	(arc
		(start 336.367882 -237.901226)
		(mid 336.252769 -238.004529)
		(end 336.18932 -238.145574)
		(width 0.088646)
		(layer "In2.Cu")
		(net "M_A_CPU0_SB_DQ<3>")
	)
	(arc
		(start 337.307682 -237.90148)
		(mid 337.025061 -237.977095)
		(end 336.742532 -237.901226)
		(width 0.088646)
		(layer "In2.Cu")
		(net "M_A_CPU0_SB_DQ<3>")
	)
	(arc
		(start 332.983332 -238.549942)
		(mid 332.796134 -238.600085)
		(end 332.608936 -238.549942)
		(width 0.088646)
		(layer "In2.Cu")
		(net "M_A_CPU0_SB_DQ<3>")
	)
	(arc
		(start 334.862932 -238.549942)
		(mid 334.675734 -238.600085)
		(end 334.488536 -238.549942)
		(width 0.088646)
		(layer "In2.Cu")
		(net "M_A_CPU0_SB_DQ<3>")
	)
	(arc
		(start 333.548736 -238.549942)
		(mid 333.266034 -238.474166)
		(end 332.983332 -238.549942)
		(width 0.088646)
		(layer "In2.Cu")
		(net "M_A_CPU0_SB_DQ<3>")
	)
	(arc
		(start 332.043532 -238.549942)
		(mid 331.95326 -238.587541)
		(end 331.856334 -238.600488)
		(width 0.088646)
		(layer "In2.Cu")
		(net "M_A_CPU0_SB_DQ<3>")
	)
	(arc
		(start 336.742532 -237.901226)
		(mid 336.555334 -237.851083)
		(end 336.368136 -237.901226)
		(width 0.088646)
		(layer "In2.Cu")
		(net "M_A_CPU0_SB_DQ<3>")
	)
	(arc
		(start 335.428336 -238.549942)
		(mid 335.145634 -238.474166)
		(end 334.862932 -238.549942)
		(width 0.088646)
		(layer "In2.Cu")
		(net "M_A_CPU0_SB_DQ<3>")
	)
	(arc
		(start 334.488536 -238.549942)
		(mid 334.205834 -238.474166)
		(end 333.923132 -238.549942)
		(width 0.088646)
		(layer "In2.Cu")
		(net "M_A_CPU0_SB_DQ<3>")
	)
	(arc
		(start 335.958942 -238.374936)
		(mid 335.894887 -238.474977)
		(end 335.802732 -238.549942)
		(width 0.088646)
		(layer "In2.Cu")
		(net "M_A_CPU0_SB_DQ<3>")
	)
	(arc
		(start 333.923132 -238.549942)
		(mid 333.735934 -238.600085)
		(end 333.548736 -238.549942)
		(width 0.088646)
		(layer "In2.Cu")
		(net "M_A_CPU0_SB_DQ<3>")
	)
	(segment
		(start 310.62168 -195.951856)
		(end 310.62168 -195.56095)
		(width 0.20066)
		(layer "F.Cu")
		(net "M_A_CPU0_SB_DQ<31>")
	)
	(segment
		(start 335.227422 -214.204296)
		(end 335.227422 -214.033608)
		(width 0.1016)
		(layer "F.Cu")
		(net "M_A_CPU0_SB_DQ<31>")
	)
	(segment
		(start 332.693772 -218.373198)
		(end 332.693772 -216.298018)
		(width 0.1016)
		(layer "F.Cu")
		(net "M_A_CPU0_SB_DQ<31>")
	)
	(segment
		(start 332.693772 -216.298018)
		(end 333.620364 -215.371426)
		(width 0.1016)
		(layer "F.Cu")
		(net "M_A_CPU0_SB_DQ<31>")
	)
	(segment
		(start 308.028086 -196.041518)
		(end 309.815738 -196.041518)
		(width 0.1016)
		(layer "F.Cu")
		(net "M_A_CPU0_SB_DQ<31>")
	)
	(segment
		(start 334.060292 -215.371426)
		(end 335.227422 -214.204296)
		(width 0.1016)
		(layer "F.Cu")
		(net "M_A_CPU0_SB_DQ<31>")
	)
	(segment
		(start 333.642716 -218.787472)
		(end 333.108046 -218.787472)
		(width 0.088646)
		(layer "F.Cu")
		(net "M_A_CPU0_SB_DQ<31>")
	)
	(segment
		(start 313.029346 -195.574412)
		(end 312.987182 -195.616576)
		(width 0.20066)
		(layer "F.Cu")
		(net "M_A_CPU0_SB_DQ<31>")
	)
	(segment
		(start 307.032406 -195.616322)
		(end 307.471064 -196.05498)
		(width 0.20066)
		(layer "F.Cu")
		(net "M_A_CPU0_SB_DQ<31>")
	)
	(segment
		(start 333.108046 -218.787472)
		(end 332.968346 -218.647772)
		(width 0.088646)
		(layer "F.Cu")
		(net "M_A_CPU0_SB_DQ<31>")
	)
	(segment
		(start 309.815738 -196.041518)
		(end 310.088026 -196.041518)
		(width 0.101854)
		(layer "F.Cu")
		(net "M_A_CPU0_SB_DQ<31>")
	)
	(segment
		(start 312.096404 -195.616576)
		(end 312.987182 -195.616576)
		(width 0.20066)
		(layer "F.Cu")
		(net "M_A_CPU0_SB_DQ<31>")
	)
	(segment
		(start 311.913778 -195.43395)
		(end 312.096404 -195.616576)
		(width 0.20066)
		(layer "F.Cu")
		(net "M_A_CPU0_SB_DQ<31>")
	)
	(segment
		(start 310.532018 -196.041518)
		(end 310.62168 -195.951856)
		(width 0.20066)
		(layer "F.Cu")
		(net "M_A_CPU0_SB_DQ<31>")
	)
	(segment
		(start 335.227422 -214.033608)
		(end 335.227422 -209.34553)
		(width 0.20066)
		(layer "F.Cu")
		(net "M_A_CPU0_SB_DQ<31>")
	)
	(segment
		(start 334.553052 -207.71739)
		(end 324.063868 -197.228206)
		(width 0.20066)
		(layer "F.Cu")
		(net "M_A_CPU0_SB_DQ<31>")
	)
	(segment
		(start 320.829686 -195.88861)
		(end 315.586364 -195.88861)
		(width 0.20066)
		(layer "F.Cu")
		(net "M_A_CPU0_SB_DQ<31>")
	)
	(segment
		(start 332.968346 -218.647772)
		(end 332.693772 -218.373198)
		(width 0.1016)
		(layer "F.Cu")
		(net "M_A_CPU0_SB_DQ<31>")
	)
	(segment
		(start 307.776372 -196.041518)
		(end 308.028086 -196.041518)
		(width 0.101854)
		(layer "F.Cu")
		(net "M_A_CPU0_SB_DQ<31>")
	)
	(segment
		(start 310.088026 -196.041518)
		(end 310.532018 -196.041518)
		(width 0.20066)
		(layer "F.Cu")
		(net "M_A_CPU0_SB_DQ<31>")
	)
	(segment
		(start 334.307942 -219.129864)
		(end 333.778606 -218.824048)
		(width 0.088646)
		(layer "F.Cu")
		(net "M_A_CPU0_SB_DQ<31>")
	)
	(segment
		(start 333.620364 -215.371426)
		(end 334.060292 -215.371426)
		(width 0.1016)
		(layer "F.Cu")
		(net "M_A_CPU0_SB_DQ<31>")
	)
	(segment
		(start 307.471064 -196.05498)
		(end 307.76291 -196.05498)
		(width 0.20066)
		(layer "F.Cu")
		(net "M_A_CPU0_SB_DQ<31>")
	)
	(segment
		(start 305.443636 -195.616322)
		(end 307.032406 -195.616322)
		(width 0.20066)
		(layer "F.Cu")
		(net "M_A_CPU0_SB_DQ<31>")
	)
	(segment
		(start 334.675734 -219.228162)
		(end 334.307942 -219.129864)
		(width 0.088646)
		(layer "F.Cu")
		(net "M_A_CPU0_SB_DQ<31>")
	)
	(segment
		(start 307.76291 -196.05498)
		(end 307.776372 -196.041518)
		(width 0.101854)
		(layer "F.Cu")
		(net "M_A_CPU0_SB_DQ<31>")
	)
	(segment
		(start 315.272166 -195.574412)
		(end 313.029346 -195.574412)
		(width 0.20066)
		(layer "F.Cu")
		(net "M_A_CPU0_SB_DQ<31>")
	)
	(segment
		(start 315.586364 -195.88861)
		(end 315.272166 -195.574412)
		(width 0.20066)
		(layer "F.Cu")
		(net "M_A_CPU0_SB_DQ<31>")
	)
	(segment
		(start 324.063868 -197.228206)
		(end 320.829686 -195.88861)
		(width 0.20066)
		(layer "F.Cu")
		(net "M_A_CPU0_SB_DQ<31>")
	)
	(segment
		(start 335.227422 -209.34553)
		(end 334.553052 -207.71739)
		(width 0.20066)
		(layer "F.Cu")
		(net "M_A_CPU0_SB_DQ<31>")
	)
	(segment
		(start 310.62168 -195.56095)
		(end 310.74868 -195.43395)
		(width 0.20066)
		(layer "F.Cu")
		(net "M_A_CPU0_SB_DQ<31>")
	)
	(segment
		(start 305.443382 -195.616576)
		(end 305.443636 -195.616322)
		(width 0.20066)
		(layer "F.Cu")
		(net "M_A_CPU0_SB_DQ<31>")
	)
	(segment
		(start 310.74868 -195.43395)
		(end 311.913778 -195.43395)
		(width 0.20066)
		(layer "F.Cu")
		(net "M_A_CPU0_SB_DQ<31>")
	)
	(arc
		(start 333.778606 -218.824048)
		(mid 333.713068 -218.796819)
		(end 333.642716 -218.787472)
		(width 0.088646)
		(layer "F.Cu")
		(net "M_A_CPU0_SB_DQ<31>")
	)
	(segment
		(start 310.62168 -197.260972)
		(end 310.74868 -197.133972)
		(width 0.20066)
		(layer "F.Cu")
		(net "M_A_CPU0_SB_DQ<30>")
	)
	(segment
		(start 333.46771 -208.441036)
		(end 323.33946 -198.312786)
		(width 0.20066)
		(layer "F.Cu")
		(net "M_A_CPU0_SB_DQ<30>")
	)
	(segment
		(start 332.084172 -216.04351)
		(end 333.947262 -214.18042)
		(width 0.1016)
		(layer "F.Cu")
		(net "M_A_CPU0_SB_DQ<30>")
	)
	(segment
		(start 332.53553 -219.080588)
		(end 332.084172 -218.62923)
		(width 0.1016)
		(layer "F.Cu")
		(net "M_A_CPU0_SB_DQ<30>")
	)
	(segment
		(start 307.76291 -197.761098)
		(end 307.796438 -197.761098)
		(width 0.101854)
		(layer "F.Cu")
		(net "M_A_CPU0_SB_DQ<30>")
	)
	(segment
		(start 333.947262 -209.598768)
		(end 333.46771 -208.441036)
		(width 0.20066)
		(layer "F.Cu")
		(net "M_A_CPU0_SB_DQ<30>")
	)
	(segment
		(start 333.3242 -219.595446)
		(end 333.145384 -219.41663)
		(width 0.088646)
		(layer "F.Cu")
		(net "M_A_CPU0_SB_DQ<30>")
	)
	(segment
		(start 323.33946 -198.312786)
		(end 320.66865 -197.206616)
		(width 0.20066)
		(layer "F.Cu")
		(net "M_A_CPU0_SB_DQ<30>")
	)
	(segment
		(start 333.947262 -214.033608)
		(end 333.947262 -209.598768)
		(width 0.20066)
		(layer "F.Cu")
		(net "M_A_CPU0_SB_DQ<30>")
	)
	(segment
		(start 335.30159 -219.595446)
		(end 333.3242 -219.595446)
		(width 0.088646)
		(layer "F.Cu")
		(net "M_A_CPU0_SB_DQ<30>")
	)
	(segment
		(start 332.084172 -218.62923)
		(end 332.084172 -216.04351)
		(width 0.1016)
		(layer "F.Cu")
		(net "M_A_CPU0_SB_DQ<30>")
	)
	(segment
		(start 332.873604 -219.41663)
		(end 332.561184 -219.10421)
		(width 0.088646)
		(layer "F.Cu")
		(net "M_A_CPU0_SB_DQ<30>")
	)
	(segment
		(start 311.919366 -197.133972)
		(end 312.101992 -197.316598)
		(width 0.20066)
		(layer "F.Cu")
		(net "M_A_CPU0_SB_DQ<30>")
	)
	(segment
		(start 335.432908 -219.726764)
		(end 335.30159 -219.595446)
		(width 0.088646)
		(layer "F.Cu")
		(net "M_A_CPU0_SB_DQ<30>")
	)
	(segment
		(start 309.821834 -197.74789)
		(end 310.088026 -197.74789)
		(width 0.101854)
		(layer "F.Cu")
		(net "M_A_CPU0_SB_DQ<30>")
	)
	(segment
		(start 332.561184 -219.10421)
		(end 332.559152 -219.10421)
		(width 0.088646)
		(layer "F.Cu")
		(net "M_A_CPU0_SB_DQ<30>")
	)
	(segment
		(start 305.443382 -197.316598)
		(end 307.03266 -197.316598)
		(width 0.20066)
		(layer "F.Cu")
		(net "M_A_CPU0_SB_DQ<30>")
	)
	(segment
		(start 307.03266 -197.316598)
		(end 307.47716 -197.761098)
		(width 0.20066)
		(layer "F.Cu")
		(net "M_A_CPU0_SB_DQ<30>")
	)
	(segment
		(start 309.815484 -197.74154)
		(end 309.821834 -197.74789)
		(width 0.1016)
		(layer "F.Cu")
		(net "M_A_CPU0_SB_DQ<30>")
	)
	(segment
		(start 335.434686 -219.971366)
		(end 335.432908 -219.726764)
		(width 0.088646)
		(layer "F.Cu")
		(net "M_A_CPU0_SB_DQ<30>")
	)
	(segment
		(start 307.814726 -197.74281)
		(end 308.024276 -197.74281)
		(width 0.101854)
		(layer "F.Cu")
		(net "M_A_CPU0_SB_DQ<30>")
	)
	(segment
		(start 313.097164 -197.206616)
		(end 312.987182 -197.316598)
		(width 0.20066)
		(layer "F.Cu")
		(net "M_A_CPU0_SB_DQ<30>")
	)
	(segment
		(start 332.559152 -219.10421)
		(end 332.53553 -219.080588)
		(width 0.088646)
		(layer "F.Cu")
		(net "M_A_CPU0_SB_DQ<30>")
	)
	(segment
		(start 307.796438 -197.761098)
		(end 307.814726 -197.74281)
		(width 0.101854)
		(layer "F.Cu")
		(net "M_A_CPU0_SB_DQ<30>")
	)
	(segment
		(start 310.74868 -197.133972)
		(end 311.919366 -197.133972)
		(width 0.20066)
		(layer "F.Cu")
		(net "M_A_CPU0_SB_DQ<30>")
	)
	(segment
		(start 335.14538 -220.041978)
		(end 335.365852 -220.040962)
		(width 0.088646)
		(layer "F.Cu")
		(net "M_A_CPU0_SB_DQ<30>")
	)
	(segment
		(start 310.62168 -197.651878)
		(end 310.62168 -197.260972)
		(width 0.20066)
		(layer "F.Cu")
		(net "M_A_CPU0_SB_DQ<30>")
	)
	(segment
		(start 335.365852 -220.040962)
		(end 335.434686 -219.971366)
		(width 0.088646)
		(layer "F.Cu")
		(net "M_A_CPU0_SB_DQ<30>")
	)
	(segment
		(start 320.66865 -197.206616)
		(end 313.097164 -197.206616)
		(width 0.20066)
		(layer "F.Cu")
		(net "M_A_CPU0_SB_DQ<30>")
	)
	(segment
		(start 333.145384 -219.41663)
		(end 332.873604 -219.41663)
		(width 0.088646)
		(layer "F.Cu")
		(net "M_A_CPU0_SB_DQ<30>")
	)
	(segment
		(start 312.101992 -197.316598)
		(end 312.987182 -197.316598)
		(width 0.20066)
		(layer "F.Cu")
		(net "M_A_CPU0_SB_DQ<30>")
	)
	(segment
		(start 333.947262 -214.18042)
		(end 333.947262 -214.033608)
		(width 0.1016)
		(layer "F.Cu")
		(net "M_A_CPU0_SB_DQ<30>")
	)
	(segment
		(start 310.525668 -197.74789)
		(end 310.62168 -197.651878)
		(width 0.20066)
		(layer "F.Cu")
		(net "M_A_CPU0_SB_DQ<30>")
	)
	(segment
		(start 307.47716 -197.761098)
		(end 307.76291 -197.761098)
		(width 0.20066)
		(layer "F.Cu")
		(net "M_A_CPU0_SB_DQ<30>")
	)
	(segment
		(start 308.028086 -197.74154)
		(end 309.815484 -197.74154)
		(width 0.1016)
		(layer "F.Cu")
		(net "M_A_CPU0_SB_DQ<30>")
	)
	(segment
		(start 308.024276 -197.74281)
		(end 308.028086 -197.74154)
		(width 0.1016)
		(layer "F.Cu")
		(net "M_A_CPU0_SB_DQ<30>")
	)
	(segment
		(start 310.088026 -197.74789)
		(end 310.525668 -197.74789)
		(width 0.20066)
		(layer "F.Cu")
		(net "M_A_CPU0_SB_DQ<30>")
	)
	(segment
		(start 309.98668 -231.741726)
		(end 307.82768 -231.741726)
		(width 0.1016)
		(layer "F.Cu")
		(net "M_A_CPU0_SB_DQ<2>")
	)
	(segment
		(start 310.609996 -231.260904)
		(end 310.609996 -231.614472)
		(width 0.20066)
		(layer "F.Cu")
		(net "M_A_CPU0_SB_DQ<2>")
	)
	(segment
		(start 307.795676 -231.750616)
		(end 307.76291 -231.750616)
		(width 0.101854)
		(layer "F.Cu")
		(net "M_A_CPU0_SB_DQ<2>")
	)
	(segment
		(start 307.76291 -231.750616)
		(end 307.540152 -231.750616)
		(width 0.20066)
		(layer "F.Cu")
		(net "M_A_CPU0_SB_DQ<2>")
	)
	(segment
		(start 337.96478 -239.57534)
		(end 337.965034 -239.0394)
		(width 0.20066)
		(layer "F.Cu")
		(net "M_A_CPU0_SB_DQ<2>")
	)
	(segment
		(start 310.088026 -231.741726)
		(end 309.98668 -231.741726)
		(width 0.101854)
		(layer "F.Cu")
		(net "M_A_CPU0_SB_DQ<2>")
	)
	(segment
		(start 307.540152 -231.750616)
		(end 307.10632 -231.316784)
		(width 0.20066)
		(layer "F.Cu")
		(net "M_A_CPU0_SB_DQ<2>")
	)
	(segment
		(start 311.26938 -231.095042)
		(end 310.775858 -231.095042)
		(width 0.20066)
		(layer "F.Cu")
		(net "M_A_CPU0_SB_DQ<2>")
	)
	(segment
		(start 310.775858 -231.095042)
		(end 310.609996 -231.260904)
		(width 0.20066)
		(layer "F.Cu")
		(net "M_A_CPU0_SB_DQ<2>")
	)
	(segment
		(start 314.092082 -231.316784)
		(end 312.987182 -231.316784)
		(width 0.20066)
		(layer "F.Cu")
		(net "M_A_CPU0_SB_DQ<2>")
	)
	(segment
		(start 311.491122 -231.316784)
		(end 311.26938 -231.095042)
		(width 0.20066)
		(layer "F.Cu")
		(net "M_A_CPU0_SB_DQ<2>")
	)
	(segment
		(start 310.482742 -231.741726)
		(end 310.088026 -231.741726)
		(width 0.20066)
		(layer "F.Cu")
		(net "M_A_CPU0_SB_DQ<2>")
	)
	(segment
		(start 312.987182 -231.316784)
		(end 311.491122 -231.316784)
		(width 0.20066)
		(layer "F.Cu")
		(net "M_A_CPU0_SB_DQ<2>")
	)
	(segment
		(start 310.609996 -231.614472)
		(end 310.482742 -231.741726)
		(width 0.20066)
		(layer "F.Cu")
		(net "M_A_CPU0_SB_DQ<2>")
	)
	(segment
		(start 307.82768 -231.741726)
		(end 307.804566 -231.741726)
		(width 0.101854)
		(layer "F.Cu")
		(net "M_A_CPU0_SB_DQ<2>")
	)
	(segment
		(start 307.804566 -231.741726)
		(end 307.795676 -231.750616)
		(width 0.101854)
		(layer "F.Cu")
		(net "M_A_CPU0_SB_DQ<2>")
	)
	(segment
		(start 307.10632 -231.316784)
		(end 305.443382 -231.316784)
		(width 0.20066)
		(layer "F.Cu")
		(net "M_A_CPU0_SB_DQ<2>")
	)
	(segment
		(start 319.428876 -232.543604)
		(end 319.514728 -232.457752)
		(width 0.18288)
		(layer "In2.Cu")
		(net "M_A_CPU0_SB_DQ<2>")
	)
	(segment
		(start 331.551788 -239.414304)
		(end 331.072744 -238.93526)
		(width 0.088646)
		(layer "In2.Cu")
		(net "M_A_CPU0_SB_DQ<2>")
	)
	(segment
		(start 320.513456 -233.183684)
		(end 320.286888 -232.957116)
		(width 0.18288)
		(layer "In2.Cu")
		(net "M_A_CPU0_SB_DQ<2>")
	)
	(segment
		(start 324.394576 -237.565184)
		(end 324.508368 -237.451392)
		(width 0.18288)
		(layer "In2.Cu")
		(net "M_A_CPU0_SB_DQ<2>")
	)
	(segment
		(start 322.510912 -235.453936)
		(end 322.510912 -235.18114)
		(width 0.18288)
		(layer "In2.Cu")
		(net "M_A_CPU0_SB_DQ<2>")
	)
	(segment
		(start 320.286888 -232.957116)
		(end 320.014092 -232.957116)
		(width 0.18288)
		(layer "In2.Cu")
		(net "M_A_CPU0_SB_DQ<2>")
	)
	(segment
		(start 322.901564 -236.062012)
		(end 322.628768 -236.062012)
		(width 0.18288)
		(layer "In2.Cu")
		(net "M_A_CPU0_SB_DQ<2>")
	)
	(segment
		(start 336.281522 -239.358678)
		(end 336.272632 -239.363758)
		(width 0.088646)
		(layer "In2.Cu")
		(net "M_A_CPU0_SB_DQ<2>")
	)
	(segment
		(start 334.407764 -239.355122)
		(end 334.393032 -239.363758)
		(width 0.088646)
		(layer "In2.Cu")
		(net "M_A_CPU0_SB_DQ<2>")
	)
	(segment
		(start 324.2818 -236.952028)
		(end 324.009004 -236.952028)
		(width 0.18288)
		(layer "In2.Cu")
		(net "M_A_CPU0_SB_DQ<2>")
	)
	(segment
		(start 319.428876 -232.8164)
		(end 319.428876 -232.543604)
		(width 0.18288)
		(layer "In2.Cu")
		(net "M_A_CPU0_SB_DQ<2>")
	)
	(segment
		(start 337.652106 -239.0394)
		(end 337.586574 -238.973868)
		(width 0.088646)
		(layer "In2.Cu")
		(net "M_A_CPU0_SB_DQ<2>")
	)
	(segment
		(start 333.467964 -239.355122)
		(end 333.453232 -239.363758)
		(width 0.088646)
		(layer "In2.Cu")
		(net "M_A_CPU0_SB_DQ<2>")
	)
	(segment
		(start 324.89394 -238.064548)
		(end 324.621144 -238.064548)
		(width 0.18288)
		(layer "In2.Cu")
		(net "M_A_CPU0_SB_DQ<2>")
	)
	(segment
		(start 336.460084 -239.023906)
		(end 336.460084 -239.0394)
		(width 0.088646)
		(layer "In2.Cu")
		(net "M_A_CPU0_SB_DQ<2>")
	)
	(segment
		(start 320.40322 -233.566716)
		(end 320.513456 -233.45648)
		(width 0.18288)
		(layer "In2.Cu")
		(net "M_A_CPU0_SB_DQ<2>")
	)
	(segment
		(start 324.009004 -236.952028)
		(end 323.900292 -237.06074)
		(width 0.18288)
		(layer "In2.Cu")
		(net "M_A_CPU0_SB_DQ<2>")
	)
	(segment
		(start 321.285616 -233.955844)
		(end 321.01282 -233.955844)
		(width 0.18288)
		(layer "In2.Cu")
		(net "M_A_CPU0_SB_DQ<2>")
	)
	(segment
		(start 323.50964 -236.452664)
		(end 323.50964 -236.179868)
		(width 0.18288)
		(layer "In2.Cu")
		(net "M_A_CPU0_SB_DQ<2>")
	)
	(segment
		(start 325.007732 -237.950756)
		(end 324.89394 -238.064548)
		(width 0.18288)
		(layer "In2.Cu")
		(net "M_A_CPU0_SB_DQ<2>")
	)
	(segment
		(start 314.650628 -231.10825)
		(end 314.300616 -231.10825)
		(width 0.18288)
		(layer "In2.Cu")
		(net "M_A_CPU0_SB_DQ<2>")
	)
	(segment
		(start 319.655444 -233.042968)
		(end 319.428876 -232.8164)
		(width 0.18288)
		(layer "In2.Cu")
		(net "M_A_CPU0_SB_DQ<2>")
	)
	(segment
		(start 337.313778 -238.553498)
		(end 337.307682 -238.549942)
		(width 0.088646)
		(layer "In2.Cu")
		(net "M_A_CPU0_SB_DQ<2>")
	)
	(segment
		(start 337.965034 -239.0394)
		(end 337.652106 -239.0394)
		(width 0.088646)
		(layer "In2.Cu")
		(net "M_A_CPU0_SB_DQ<2>")
	)
	(segment
		(start 319.514728 -232.457752)
		(end 319.514728 -232.184956)
		(width 0.18288)
		(layer "In2.Cu")
		(net "M_A_CPU0_SB_DQ<2>")
	)
	(segment
		(start 321.899534 -235.066586)
		(end 321.626738 -235.066586)
		(width 0.18288)
		(layer "In2.Cu")
		(net "M_A_CPU0_SB_DQ<2>")
	)
	(segment
		(start 323.400928 -236.561376)
		(end 323.50964 -236.452664)
		(width 0.18288)
		(layer "In2.Cu")
		(net "M_A_CPU0_SB_DQ<2>")
	)
	(segment
		(start 323.50964 -236.179868)
		(end 323.283072 -235.9533)
		(width 0.18288)
		(layer "In2.Cu")
		(net "M_A_CPU0_SB_DQ<2>")
	)
	(segment
		(start 323.010276 -235.9533)
		(end 322.901564 -236.062012)
		(width 0.18288)
		(layer "In2.Cu")
		(net "M_A_CPU0_SB_DQ<2>")
	)
	(segment
		(start 322.4022 -235.835444)
		(end 322.4022 -235.562648)
		(width 0.18288)
		(layer "In2.Cu")
		(net "M_A_CPU0_SB_DQ<2>")
	)
	(segment
		(start 314.300616 -231.10825)
		(end 314.092082 -231.316784)
		(width 0.18288)
		(layer "In2.Cu")
		(net "M_A_CPU0_SB_DQ<2>")
	)
	(segment
		(start 322.510912 -235.18114)
		(end 322.284344 -234.954572)
		(width 0.18288)
		(layer "In2.Cu")
		(net "M_A_CPU0_SB_DQ<2>")
	)
	(segment
		(start 330.699364 -238.93526)
		(end 326.265032 -238.93526)
		(width 0.18288)
		(layer "In2.Cu")
		(net "M_A_CPU0_SB_DQ<2>")
	)
	(segment
		(start 321.40017 -234.840018)
		(end 321.40017 -234.567222)
		(width 0.18288)
		(layer "In2.Cu")
		(net "M_A_CPU0_SB_DQ<2>")
	)
	(segment
		(start 323.283072 -235.9533)
		(end 323.010276 -235.9533)
		(width 0.18288)
		(layer "In2.Cu")
		(net "M_A_CPU0_SB_DQ<2>")
	)
	(segment
		(start 320.513456 -233.45648)
		(end 320.513456 -233.183684)
		(width 0.18288)
		(layer "In2.Cu")
		(net "M_A_CPU0_SB_DQ<2>")
	)
	(segment
		(start 314.976256 -231.433878)
		(end 314.650628 -231.10825)
		(width 0.18288)
		(layer "In2.Cu")
		(net "M_A_CPU0_SB_DQ<2>")
	)
	(segment
		(start 322.628768 -236.062012)
		(end 322.4022 -235.835444)
		(width 0.18288)
		(layer "In2.Cu")
		(net "M_A_CPU0_SB_DQ<2>")
	)
	(segment
		(start 324.394576 -237.83798)
		(end 324.394576 -237.565184)
		(width 0.18288)
		(layer "In2.Cu")
		(net "M_A_CPU0_SB_DQ<2>")
	)
	(segment
		(start 323.400928 -236.834172)
		(end 323.400928 -236.561376)
		(width 0.18288)
		(layer "In2.Cu")
		(net "M_A_CPU0_SB_DQ<2>")
	)
	(segment
		(start 320.40322 -233.839512)
		(end 320.40322 -233.566716)
		(width 0.18288)
		(layer "In2.Cu")
		(net "M_A_CPU0_SB_DQ<2>")
	)
	(segment
		(start 320.902584 -234.06608)
		(end 320.629788 -234.06608)
		(width 0.18288)
		(layer "In2.Cu")
		(net "M_A_CPU0_SB_DQ<2>")
	)
	(segment
		(start 320.014092 -232.957116)
		(end 319.92824 -233.042968)
		(width 0.18288)
		(layer "In2.Cu")
		(net "M_A_CPU0_SB_DQ<2>")
	)
	(segment
		(start 321.40017 -234.567222)
		(end 321.512184 -234.455208)
		(width 0.18288)
		(layer "In2.Cu")
		(net "M_A_CPU0_SB_DQ<2>")
	)
	(segment
		(start 321.626738 -235.066586)
		(end 321.40017 -234.840018)
		(width 0.18288)
		(layer "In2.Cu")
		(net "M_A_CPU0_SB_DQ<2>")
	)
	(segment
		(start 319.92824 -233.042968)
		(end 319.655444 -233.042968)
		(width 0.18288)
		(layer "In2.Cu")
		(net "M_A_CPU0_SB_DQ<2>")
	)
	(segment
		(start 323.627496 -237.06074)
		(end 323.400928 -236.834172)
		(width 0.18288)
		(layer "In2.Cu")
		(net "M_A_CPU0_SB_DQ<2>")
	)
	(segment
		(start 332.326234 -239.414304)
		(end 331.551788 -239.414304)
		(width 0.088646)
		(layer "In2.Cu")
		(net "M_A_CPU0_SB_DQ<2>")
	)
	(segment
		(start 322.4022 -235.562648)
		(end 322.510912 -235.453936)
		(width 0.18288)
		(layer "In2.Cu")
		(net "M_A_CPU0_SB_DQ<2>")
	)
	(segment
		(start 320.629788 -234.06608)
		(end 320.40322 -233.839512)
		(width 0.18288)
		(layer "In2.Cu")
		(net "M_A_CPU0_SB_DQ<2>")
	)
	(segment
		(start 319.514728 -232.184956)
		(end 319.157096 -231.827324)
		(width 0.18288)
		(layer "In2.Cu")
		(net "M_A_CPU0_SB_DQ<2>")
	)
	(segment
		(start 321.512184 -234.182412)
		(end 321.285616 -233.955844)
		(width 0.18288)
		(layer "In2.Cu")
		(net "M_A_CPU0_SB_DQ<2>")
	)
	(segment
		(start 321.01282 -233.955844)
		(end 320.902584 -234.06608)
		(width 0.18288)
		(layer "In2.Cu")
		(net "M_A_CPU0_SB_DQ<2>")
	)
	(segment
		(start 324.621144 -238.064548)
		(end 324.394576 -237.83798)
		(width 0.18288)
		(layer "In2.Cu")
		(net "M_A_CPU0_SB_DQ<2>")
	)
	(segment
		(start 326.265032 -238.93526)
		(end 325.280528 -237.950756)
		(width 0.18288)
		(layer "In2.Cu")
		(net "M_A_CPU0_SB_DQ<2>")
	)
	(segment
		(start 322.284344 -234.954572)
		(end 322.011548 -234.954572)
		(width 0.18288)
		(layer "In2.Cu")
		(net "M_A_CPU0_SB_DQ<2>")
	)
	(segment
		(start 337.307682 -238.549942)
		(end 337.29295 -238.541306)
		(width 0.088646)
		(layer "In2.Cu")
		(net "M_A_CPU0_SB_DQ<2>")
	)
	(segment
		(start 321.512184 -234.455208)
		(end 321.512184 -234.182412)
		(width 0.18288)
		(layer "In2.Cu")
		(net "M_A_CPU0_SB_DQ<2>")
	)
	(segment
		(start 331.072744 -238.93526)
		(end 330.699364 -238.93526)
		(width 0.088646)
		(layer "In2.Cu")
		(net "M_A_CPU0_SB_DQ<2>")
	)
	(segment
		(start 319.157096 -231.827324)
		(end 315.92647 -231.827324)
		(width 0.18288)
		(layer "In2.Cu")
		(net "M_A_CPU0_SB_DQ<2>")
	)
	(segment
		(start 325.280528 -237.950756)
		(end 325.007732 -237.950756)
		(width 0.18288)
		(layer "In2.Cu")
		(net "M_A_CPU0_SB_DQ<2>")
	)
	(segment
		(start 322.011548 -234.954572)
		(end 321.899534 -235.066586)
		(width 0.18288)
		(layer "In2.Cu")
		(net "M_A_CPU0_SB_DQ<2>")
	)
	(segment
		(start 324.508368 -237.178596)
		(end 324.2818 -236.952028)
		(width 0.18288)
		(layer "In2.Cu")
		(net "M_A_CPU0_SB_DQ<2>")
	)
	(segment
		(start 324.508368 -237.451392)
		(end 324.508368 -237.178596)
		(width 0.18288)
		(layer "In2.Cu")
		(net "M_A_CPU0_SB_DQ<2>")
	)
	(segment
		(start 315.92647 -231.827324)
		(end 314.976256 -231.433878)
		(width 0.18288)
		(layer "In2.Cu")
		(net "M_A_CPU0_SB_DQ<2>")
	)
	(segment
		(start 323.900292 -237.06074)
		(end 323.627496 -237.06074)
		(width 0.18288)
		(layer "In2.Cu")
		(net "M_A_CPU0_SB_DQ<2>")
	)
	(segment
		(start 335.347564 -239.355122)
		(end 335.332832 -239.363758)
		(width 0.088646)
		(layer "In2.Cu")
		(net "M_A_CPU0_SB_DQ<2>")
	)
	(arc
		(start 334.393032 -239.363758)
		(mid 334.205834 -239.413901)
		(end 334.018636 -239.363758)
		(width 0.088646)
		(layer "In2.Cu")
		(net "M_A_CPU0_SB_DQ<2>")
	)
	(arc
		(start 337.586574 -238.973868)
		(mid 337.49933 -238.73178)
		(end 337.313778 -238.553498)
		(width 0.088646)
		(layer "In2.Cu")
		(net "M_A_CPU0_SB_DQ<2>")
	)
	(arc
		(start 336.272632 -239.363758)
		(mid 336.085434 -239.413901)
		(end 335.898236 -239.363758)
		(width 0.088646)
		(layer "In2.Cu")
		(net "M_A_CPU0_SB_DQ<2>")
	)
	(arc
		(start 334.958436 -239.363758)
		(mid 334.684237 -239.287923)
		(end 334.407764 -239.355122)
		(width 0.088646)
		(layer "In2.Cu")
		(net "M_A_CPU0_SB_DQ<2>")
	)
	(arc
		(start 332.528164 -239.355122)
		(mid 332.431437 -239.399174)
		(end 332.326234 -239.414304)
		(width 0.088646)
		(layer "In2.Cu")
		(net "M_A_CPU0_SB_DQ<2>")
	)
	(arc
		(start 335.332832 -239.363758)
		(mid 335.145634 -239.413901)
		(end 334.958436 -239.363758)
		(width 0.088646)
		(layer "In2.Cu")
		(net "M_A_CPU0_SB_DQ<2>")
	)
	(arc
		(start 336.460084 -239.0394)
		(mid 336.412405 -239.2223)
		(end 336.281522 -239.358678)
		(width 0.088646)
		(layer "In2.Cu")
		(net "M_A_CPU0_SB_DQ<2>")
	)
	(arc
		(start 336.742278 -238.549942)
		(mid 336.539455 -238.750173)
		(end 336.460084 -239.023906)
		(width 0.088646)
		(layer "In2.Cu")
		(net "M_A_CPU0_SB_DQ<2>")
	)
	(arc
		(start 335.898236 -239.363758)
		(mid 335.624037 -239.287923)
		(end 335.347564 -239.355122)
		(width 0.088646)
		(layer "In2.Cu")
		(net "M_A_CPU0_SB_DQ<2>")
	)
	(arc
		(start 334.018636 -239.363758)
		(mid 333.744437 -239.287923)
		(end 333.467964 -239.355122)
		(width 0.088646)
		(layer "In2.Cu")
		(net "M_A_CPU0_SB_DQ<2>")
	)
	(arc
		(start 333.078836 -239.363758)
		(mid 332.804637 -239.287923)
		(end 332.528164 -239.355122)
		(width 0.088646)
		(layer "In2.Cu")
		(net "M_A_CPU0_SB_DQ<2>")
	)
	(arc
		(start 337.29295 -238.541306)
		(mid 337.016475 -238.473986)
		(end 336.742278 -238.549942)
		(width 0.088646)
		(layer "In2.Cu")
		(net "M_A_CPU0_SB_DQ<2>")
	)
	(arc
		(start 333.453232 -239.363758)
		(mid 333.266034 -239.413901)
		(end 333.078836 -239.363758)
		(width 0.088646)
		(layer "In2.Cu")
		(net "M_A_CPU0_SB_DQ<2>")
	)
	(segment
		(start 332.388972 -218.49969)
		(end 332.388972 -216.17051)
		(width 0.1016)
		(layer "F.Cu")
		(net "M_A_CPU0_SB_DQ<29>")
	)
	(segment
		(start 303.295304 -196.718428)
		(end 303.523396 -196.490336)
		(width 0.20066)
		(layer "F.Cu")
		(net "M_A_CPU0_SB_DQ<29>")
	)
	(segment
		(start 314.916312 -196.55409)
		(end 314.40374 -196.041518)
		(width 0.20066)
		(layer "F.Cu")
		(net "M_A_CPU0_SB_DQ<29>")
	)
	(segment
		(start 304.319178 -196.031104)
		(end 304.353214 -196.041518)
		(width 0.1016)
		(layer "F.Cu")
		(net "M_A_CPU0_SB_DQ<29>")
	)
	(segment
		(start 301.343314 -196.466714)
		(end 302.653446 -196.466714)
		(width 0.20066)
		(layer "F.Cu")
		(net "M_A_CPU0_SB_DQ<29>")
	)
	(segment
		(start 304.353214 -196.041518)
		(end 306.289202 -196.041518)
		(width 0.1016)
		(layer "F.Cu")
		(net "M_A_CPU0_SB_DQ<29>")
	)
	(segment
		(start 306.79898 -196.041518)
		(end 307.224176 -196.466714)
		(width 0.20066)
		(layer "F.Cu")
		(net "M_A_CPU0_SB_DQ<29>")
	)
	(segment
		(start 334.587342 -214.203534)
		(end 334.587342 -214.033608)
		(width 0.1016)
		(layer "F.Cu")
		(net "M_A_CPU0_SB_DQ<29>")
	)
	(segment
		(start 303.523396 -196.490336)
		(end 303.523396 -196.196204)
		(width 0.20066)
		(layer "F.Cu")
		(net "M_A_CPU0_SB_DQ<29>")
	)
	(segment
		(start 333.51597 -215.043512)
		(end 333.747364 -215.043512)
		(width 0.1016)
		(layer "F.Cu")
		(net "M_A_CPU0_SB_DQ<29>")
	)
	(segment
		(start 332.921864 -219.032582)
		(end 332.7527 -218.863418)
		(width 0.088646)
		(layer "F.Cu")
		(net "M_A_CPU0_SB_DQ<29>")
	)
	(segment
		(start 333.747364 -215.043512)
		(end 334.587342 -214.203534)
		(width 0.1016)
		(layer "F.Cu")
		(net "M_A_CPU0_SB_DQ<29>")
	)
	(segment
		(start 314.40374 -196.041518)
		(end 314.17768 -196.041518)
		(width 0.20066)
		(layer "F.Cu")
		(net "M_A_CPU0_SB_DQ<29>")
	)
	(segment
		(start 307.224176 -196.466714)
		(end 308.887114 -196.466714)
		(width 0.20066)
		(layer "F.Cu")
		(net "M_A_CPU0_SB_DQ<29>")
	)
	(segment
		(start 311.553352 -196.035168)
		(end 311.121806 -196.466714)
		(width 0.20066)
		(layer "F.Cu")
		(net "M_A_CPU0_SB_DQ<29>")
	)
	(segment
		(start 320.764916 -196.55409)
		(end 314.916312 -196.55409)
		(width 0.20066)
		(layer "F.Cu")
		(net "M_A_CPU0_SB_DQ<29>")
	)
	(segment
		(start 306.289202 -196.041518)
		(end 306.644294 -196.041518)
		(width 0.101854)
		(layer "F.Cu")
		(net "M_A_CPU0_SB_DQ<29>")
	)
	(segment
		(start 311.86628 -196.035168)
		(end 311.553352 -196.035168)
		(width 0.20066)
		(layer "F.Cu")
		(net "M_A_CPU0_SB_DQ<29>")
	)
	(segment
		(start 303.688496 -196.031104)
		(end 304.319178 -196.031104)
		(width 0.20066)
		(layer "F.Cu")
		(net "M_A_CPU0_SB_DQ<29>")
	)
	(segment
		(start 303.523396 -196.196204)
		(end 303.688496 -196.031104)
		(width 0.20066)
		(layer "F.Cu")
		(net "M_A_CPU0_SB_DQ<29>")
	)
	(segment
		(start 311.87263 -196.041518)
		(end 311.86628 -196.035168)
		(width 0.1016)
		(layer "F.Cu")
		(net "M_A_CPU0_SB_DQ<29>")
	)
	(segment
		(start 311.121806 -196.466714)
		(end 308.887114 -196.466714)
		(width 0.20066)
		(layer "F.Cu")
		(net "M_A_CPU0_SB_DQ<29>")
	)
	(segment
		(start 332.388972 -216.17051)
		(end 333.51597 -215.043512)
		(width 0.1016)
		(layer "F.Cu")
		(net "M_A_CPU0_SB_DQ<29>")
	)
	(segment
		(start 314.17768 -196.041518)
		(end 311.87263 -196.041518)
		(width 0.1016)
		(layer "F.Cu")
		(net "M_A_CPU0_SB_DQ<29>")
	)
	(segment
		(start 323.701664 -197.770496)
		(end 320.764916 -196.55409)
		(width 0.20066)
		(layer "F.Cu")
		(net "M_A_CPU0_SB_DQ<29>")
	)
	(segment
		(start 334.587342 -209.472022)
		(end 334.010254 -208.079086)
		(width 0.20066)
		(layer "F.Cu")
		(net "M_A_CPU0_SB_DQ<29>")
	)
	(segment
		(start 334.010254 -208.079086)
		(end 323.701664 -197.770496)
		(width 0.20066)
		(layer "F.Cu")
		(net "M_A_CPU0_SB_DQ<29>")
	)
	(segment
		(start 333.735934 -219.228162)
		(end 332.921864 -219.032582)
		(width 0.088646)
		(layer "F.Cu")
		(net "M_A_CPU0_SB_DQ<29>")
	)
	(segment
		(start 302.90516 -196.718428)
		(end 303.295304 -196.718428)
		(width 0.20066)
		(layer "F.Cu")
		(net "M_A_CPU0_SB_DQ<29>")
	)
	(segment
		(start 332.7527 -218.863418)
		(end 332.388972 -218.49969)
		(width 0.1016)
		(layer "F.Cu")
		(net "M_A_CPU0_SB_DQ<29>")
	)
	(segment
		(start 302.653446 -196.466714)
		(end 302.90516 -196.718428)
		(width 0.20066)
		(layer "F.Cu")
		(net "M_A_CPU0_SB_DQ<29>")
	)
	(segment
		(start 306.644294 -196.041518)
		(end 306.79898 -196.041518)
		(width 0.20066)
		(layer "F.Cu")
		(net "M_A_CPU0_SB_DQ<29>")
	)
	(segment
		(start 334.587342 -214.033608)
		(end 334.587342 -209.472022)
		(width 0.20066)
		(layer "F.Cu")
		(net "M_A_CPU0_SB_DQ<29>")
	)
	(segment
		(start 304.343308 -197.741794)
		(end 306.313586 -197.741794)
		(width 0.1016)
		(layer "F.Cu")
		(net "M_A_CPU0_SB_DQ<28>")
	)
	(segment
		(start 331.779372 -215.91651)
		(end 333.30769 -214.388192)
		(width 0.1016)
		(layer "F.Cu")
		(net "M_A_CPU0_SB_DQ<28>")
	)
	(segment
		(start 333.30769 -214.033608)
		(end 333.30769 -209.726276)
		(width 0.20066)
		(layer "F.Cu")
		(net "M_A_CPU0_SB_DQ<28>")
	)
	(segment
		(start 303.324514 -198.418958)
		(end 303.54778 -198.195692)
		(width 0.20066)
		(layer "F.Cu")
		(net "M_A_CPU0_SB_DQ<28>")
	)
	(segment
		(start 311.84088 -197.73265)
		(end 311.201308 -197.73265)
		(width 0.20066)
		(layer "F.Cu")
		(net "M_A_CPU0_SB_DQ<28>")
	)
	(segment
		(start 310.767222 -198.166736)
		(end 308.887114 -198.166736)
		(width 0.20066)
		(layer "F.Cu")
		(net "M_A_CPU0_SB_DQ<28>")
	)
	(segment
		(start 333.30769 -209.726276)
		(end 332.92542 -208.803494)
		(width 0.20066)
		(layer "F.Cu")
		(net "M_A_CPU0_SB_DQ<28>")
	)
	(segment
		(start 333.30769 -214.388192)
		(end 333.30769 -214.033608)
		(width 0.1016)
		(layer "F.Cu")
		(net "M_A_CPU0_SB_DQ<28>")
	)
	(segment
		(start 304.319178 -197.734428)
		(end 304.343308 -197.741794)
		(width 0.1016)
		(layer "F.Cu")
		(net "M_A_CPU0_SB_DQ<28>")
	)
	(segment
		(start 303.54778 -198.195692)
		(end 303.54778 -197.89648)
		(width 0.20066)
		(layer "F.Cu")
		(net "M_A_CPU0_SB_DQ<28>")
	)
	(segment
		(start 306.313586 -197.741794)
		(end 306.644294 -197.741794)
		(width 0.101854)
		(layer "F.Cu")
		(net "M_A_CPU0_SB_DQ<28>")
	)
	(segment
		(start 303.709832 -197.734428)
		(end 304.319178 -197.734428)
		(width 0.20066)
		(layer "F.Cu")
		(net "M_A_CPU0_SB_DQ<28>")
	)
	(segment
		(start 311.84977 -197.74154)
		(end 311.84088 -197.73265)
		(width 0.101854)
		(layer "F.Cu")
		(net "M_A_CPU0_SB_DQ<28>")
	)
	(segment
		(start 312.12536 -197.74154)
		(end 311.84977 -197.74154)
		(width 0.101854)
		(layer "F.Cu")
		(net "M_A_CPU0_SB_DQ<28>")
	)
	(segment
		(start 332.80604 -219.78239)
		(end 332.319884 -219.296234)
		(width 0.088646)
		(layer "F.Cu")
		(net "M_A_CPU0_SB_DQ<28>")
	)
	(segment
		(start 314.607194 -197.99046)
		(end 314.358274 -197.74154)
		(width 0.20066)
		(layer "F.Cu")
		(net "M_A_CPU0_SB_DQ<28>")
	)
	(segment
		(start 302.929798 -198.418958)
		(end 303.324514 -198.418958)
		(width 0.20066)
		(layer "F.Cu")
		(net "M_A_CPU0_SB_DQ<28>")
	)
	(segment
		(start 331.779372 -218.755722)
		(end 331.779372 -215.91651)
		(width 0.1016)
		(layer "F.Cu")
		(net "M_A_CPU0_SB_DQ<28>")
	)
	(segment
		(start 307.297074 -198.166736)
		(end 308.887114 -198.166736)
		(width 0.20066)
		(layer "F.Cu")
		(net "M_A_CPU0_SB_DQ<28>")
	)
	(segment
		(start 333.004668 -219.78239)
		(end 332.80604 -219.78239)
		(width 0.088646)
		(layer "F.Cu")
		(net "M_A_CPU0_SB_DQ<28>")
	)
	(segment
		(start 314.174886 -197.74154)
		(end 312.12536 -197.74154)
		(width 0.1016)
		(layer "F.Cu")
		(net "M_A_CPU0_SB_DQ<28>")
	)
	(segment
		(start 333.26578 -220.041978)
		(end 333.004668 -219.78239)
		(width 0.088646)
		(layer "F.Cu")
		(net "M_A_CPU0_SB_DQ<28>")
	)
	(segment
		(start 332.92542 -208.803494)
		(end 322.977256 -198.85533)
		(width 0.20066)
		(layer "F.Cu")
		(net "M_A_CPU0_SB_DQ<28>")
	)
	(segment
		(start 302.677576 -198.166736)
		(end 302.929798 -198.418958)
		(width 0.20066)
		(layer "F.Cu")
		(net "M_A_CPU0_SB_DQ<28>")
	)
	(segment
		(start 301.343314 -198.166736)
		(end 302.677576 -198.166736)
		(width 0.20066)
		(layer "F.Cu")
		(net "M_A_CPU0_SB_DQ<28>")
	)
	(segment
		(start 332.319884 -219.296234)
		(end 331.779372 -218.755722)
		(width 0.1016)
		(layer "F.Cu")
		(net "M_A_CPU0_SB_DQ<28>")
	)
	(segment
		(start 306.872132 -197.741794)
		(end 307.297074 -198.166736)
		(width 0.20066)
		(layer "F.Cu")
		(net "M_A_CPU0_SB_DQ<28>")
	)
	(segment
		(start 306.644294 -197.741794)
		(end 306.872132 -197.741794)
		(width 0.20066)
		(layer "F.Cu")
		(net "M_A_CPU0_SB_DQ<28>")
	)
	(segment
		(start 314.358274 -197.74154)
		(end 314.17768 -197.74154)
		(width 0.20066)
		(layer "F.Cu")
		(net "M_A_CPU0_SB_DQ<28>")
	)
	(segment
		(start 311.201308 -197.73265)
		(end 310.767222 -198.166736)
		(width 0.20066)
		(layer "F.Cu")
		(net "M_A_CPU0_SB_DQ<28>")
	)
	(segment
		(start 314.17768 -197.74154)
		(end 314.174886 -197.74154)
		(width 0.101854)
		(layer "F.Cu")
		(net "M_A_CPU0_SB_DQ<28>")
	)
	(segment
		(start 303.54778 -197.89648)
		(end 303.709832 -197.734428)
		(width 0.20066)
		(layer "F.Cu")
		(net "M_A_CPU0_SB_DQ<28>")
	)
	(segment
		(start 322.977256 -198.85533)
		(end 320.889376 -197.99046)
		(width 0.20066)
		(layer "F.Cu")
		(net "M_A_CPU0_SB_DQ<28>")
	)
	(segment
		(start 320.889376 -197.99046)
		(end 314.607194 -197.99046)
		(width 0.20066)
		(layer "F.Cu")
		(net "M_A_CPU0_SB_DQ<28>")
	)
	(segment
		(start 321.778122 -202.786488)
		(end 322.204842 -202.360276)
		(width 0.20066)
		(layer "F.Cu")
		(net "M_A_CPU0_SB_DQ<27>")
	)
	(segment
		(start 330.255372 -215.278462)
		(end 330.731876 -214.801958)
		(width 0.1016)
		(layer "F.Cu")
		(net "M_A_CPU0_SB_DQ<27>")
	)
	(segment
		(start 311.708546 -201.908664)
		(end 312.070242 -201.908664)
		(width 0.20066)
		(layer "F.Cu")
		(net "M_A_CPU0_SB_DQ<27>")
	)
	(segment
		(start 323.286882 -204.295248)
		(end 323.003672 -204.295248)
		(width 0.20066)
		(layer "F.Cu")
		(net "M_A_CPU0_SB_DQ<27>")
	)
	(segment
		(start 335.398618 -221.638368)
		(end 335.587594 -221.449392)
		(width 0.088646)
		(layer "F.Cu")
		(net "M_A_CPU0_SB_DQ<27>")
	)
	(segment
		(start 312.41238 -201.566526)
		(end 312.412634 -201.56678)
		(width 0.20066)
		(layer "F.Cu")
		(net "M_A_CPU0_SB_DQ<27>")
	)
	(segment
		(start 313.488832 -201.566526)
		(end 313.488578 -201.56678)
		(width 0.20066)
		(layer "F.Cu")
		(net "M_A_CPU0_SB_DQ<27>")
	)
	(segment
		(start 314.808616 -201.545952)
		(end 314.586366 -201.768202)
		(width 0.20066)
		(layer "F.Cu")
		(net "M_A_CPU0_SB_DQ<27>")
	)
	(segment
		(start 322.784216 -204.075792)
		(end 322.784216 -203.792074)
		(width 0.20066)
		(layer "F.Cu")
		(net "M_A_CPU0_SB_DQ<27>")
	)
	(segment
		(start 332.79969 -221.442026)
		(end 332.303628 -221.442026)
		(width 0.088646)
		(layer "F.Cu")
		(net "M_A_CPU0_SB_DQ<27>")
	)
	(segment
		(start 334.654906 -221.504256)
		(end 334.381856 -221.346268)
		(width 0.088646)
		(layer "F.Cu")
		(net "M_A_CPU0_SB_DQ<27>")
	)
	(segment
		(start 335.587594 -221.307152)
		(end 335.49463 -221.214188)
		(width 0.088646)
		(layer "F.Cu")
		(net "M_A_CPU0_SB_DQ<27>")
	)
	(segment
		(start 307.80228 -201.991722)
		(end 310.053482 -201.991722)
		(width 0.1016)
		(layer "F.Cu")
		(net "M_A_CPU0_SB_DQ<27>")
	)
	(segment
		(start 335.294732 -221.214188)
		(end 334.87868 -221.386908)
		(width 0.088646)
		(layer "F.Cu")
		(net "M_A_CPU0_SB_DQ<27>")
	)
	(segment
		(start 322.204842 -202.360276)
		(end 322.204842 -202.076812)
		(width 0.20066)
		(layer "F.Cu")
		(net "M_A_CPU0_SB_DQ<27>")
	)
	(segment
		(start 322.991226 -202.863196)
		(end 322.707762 -202.863196)
		(width 0.20066)
		(layer "F.Cu")
		(net "M_A_CPU0_SB_DQ<27>")
	)
	(segment
		(start 323.003672 -204.295248)
		(end 322.784216 -204.075792)
		(width 0.20066)
		(layer "F.Cu")
		(net "M_A_CPU0_SB_DQ<27>")
	)
	(segment
		(start 322.204842 -202.076812)
		(end 321.673982 -201.545952)
		(width 0.20066)
		(layer "F.Cu")
		(net "M_A_CPU0_SB_DQ<27>")
	)
	(segment
		(start 333.012288 -221.345506)
		(end 332.884526 -221.419166)
		(width 0.088646)
		(layer "F.Cu")
		(net "M_A_CPU0_SB_DQ<27>")
	)
	(segment
		(start 312.070242 -201.908664)
		(end 312.41238 -201.566526)
		(width 0.20066)
		(layer "F.Cu")
		(net "M_A_CPU0_SB_DQ<27>")
	)
	(segment
		(start 307.126132 -201.56678)
		(end 307.567076 -202.007724)
		(width 0.20066)
		(layer "F.Cu")
		(net "M_A_CPU0_SB_DQ<27>")
	)
	(segment
		(start 310.322976 -202.026266)
		(end 310.862472 -201.48677)
		(width 0.20066)
		(layer "F.Cu")
		(net "M_A_CPU0_SB_DQ<27>")
	)
	(segment
		(start 307.567076 -202.007724)
		(end 307.76291 -202.007724)
		(width 0.20066)
		(layer "F.Cu")
		(net "M_A_CPU0_SB_DQ<27>")
	)
	(segment
		(start 310.862472 -201.48677)
		(end 311.286652 -201.48677)
		(width 0.20066)
		(layer "F.Cu")
		(net "M_A_CPU0_SB_DQ<27>")
	)
	(segment
		(start 323.997066 -203.869036)
		(end 323.713602 -203.869036)
		(width 0.20066)
		(layer "F.Cu")
		(net "M_A_CPU0_SB_DQ<27>")
	)
	(segment
		(start 332.303628 -221.442026)
		(end 332.11516 -221.253558)
		(width 0.088646)
		(layer "F.Cu")
		(net "M_A_CPU0_SB_DQ<27>")
	)
	(segment
		(start 330.255372 -219.39377)
		(end 330.255372 -215.278462)
		(width 0.1016)
		(layer "F.Cu")
		(net "M_A_CPU0_SB_DQ<27>")
	)
	(segment
		(start 310.088026 -202.026266)
		(end 310.322976 -202.026266)
		(width 0.20066)
		(layer "F.Cu")
		(net "M_A_CPU0_SB_DQ<27>")
	)
	(segment
		(start 313.690508 -201.768202)
		(end 313.488832 -201.566526)
		(width 0.20066)
		(layer "F.Cu")
		(net "M_A_CPU0_SB_DQ<27>")
	)
	(segment
		(start 322.707762 -202.863196)
		(end 322.281042 -203.289408)
		(width 0.20066)
		(layer "F.Cu")
		(net "M_A_CPU0_SB_DQ<27>")
	)
	(segment
		(start 312.412634 -201.56678)
		(end 312.987182 -201.56678)
		(width 0.20066)
		(layer "F.Cu")
		(net "M_A_CPU0_SB_DQ<27>")
	)
	(segment
		(start 321.673982 -201.545952)
		(end 314.808616 -201.545952)
		(width 0.20066)
		(layer "F.Cu")
		(net "M_A_CPU0_SB_DQ<27>")
	)
	(segment
		(start 322.784216 -203.792074)
		(end 323.210682 -203.366116)
		(width 0.20066)
		(layer "F.Cu")
		(net "M_A_CPU0_SB_DQ<27>")
	)
	(segment
		(start 333.852774 -221.345506)
		(end 333.452978 -221.345506)
		(width 0.088646)
		(layer "F.Cu")
		(net "M_A_CPU0_SB_DQ<27>")
	)
	(segment
		(start 330.731876 -214.033608)
		(end 330.731876 -210.603846)
		(width 0.20066)
		(layer "F.Cu")
		(net "M_A_CPU0_SB_DQ<27>")
	)
	(segment
		(start 335.587594 -221.449392)
		(end 335.587594 -221.307152)
		(width 0.088646)
		(layer "F.Cu")
		(net "M_A_CPU0_SB_DQ<27>")
	)
	(segment
		(start 313.488578 -201.56678)
		(end 312.987182 -201.56678)
		(width 0.20066)
		(layer "F.Cu")
		(net "M_A_CPU0_SB_DQ<27>")
	)
	(segment
		(start 323.210682 -203.082652)
		(end 322.991226 -202.863196)
		(width 0.20066)
		(layer "F.Cu")
		(net "M_A_CPU0_SB_DQ<27>")
	)
	(segment
		(start 323.210682 -203.366116)
		(end 323.210682 -203.082652)
		(width 0.20066)
		(layer "F.Cu")
		(net "M_A_CPU0_SB_DQ<27>")
	)
	(segment
		(start 335.49463 -221.214188)
		(end 335.294732 -221.214188)
		(width 0.088646)
		(layer "F.Cu")
		(net "M_A_CPU0_SB_DQ<27>")
	)
	(segment
		(start 334.761332 -221.504256)
		(end 334.654906 -221.504256)
		(width 0.088646)
		(layer "F.Cu")
		(net "M_A_CPU0_SB_DQ<27>")
	)
	(segment
		(start 330.731876 -210.603846)
		(end 323.997066 -203.869036)
		(width 0.20066)
		(layer "F.Cu")
		(net "M_A_CPU0_SB_DQ<27>")
	)
	(segment
		(start 330.731876 -214.801958)
		(end 330.731876 -214.033608)
		(width 0.1016)
		(layer "F.Cu")
		(net "M_A_CPU0_SB_DQ<27>")
	)
	(segment
		(start 332.11516 -221.253558)
		(end 330.255372 -219.39377)
		(width 0.1016)
		(layer "F.Cu")
		(net "M_A_CPU0_SB_DQ<27>")
	)
	(segment
		(start 335.176876 -221.638368)
		(end 335.398618 -221.638368)
		(width 0.088646)
		(layer "F.Cu")
		(net "M_A_CPU0_SB_DQ<27>")
	)
	(segment
		(start 322.281042 -203.289408)
		(end 321.997578 -203.289408)
		(width 0.20066)
		(layer "F.Cu")
		(net "M_A_CPU0_SB_DQ<27>")
	)
	(segment
		(start 314.586366 -201.768202)
		(end 313.690508 -201.768202)
		(width 0.20066)
		(layer "F.Cu")
		(net "M_A_CPU0_SB_DQ<27>")
	)
	(segment
		(start 334.188562 -221.23527)
		(end 333.96301 -221.23527)
		(width 0.088646)
		(layer "F.Cu")
		(net "M_A_CPU0_SB_DQ<27>")
	)
	(segment
		(start 334.254094 -221.300802)
		(end 334.188562 -221.23527)
		(width 0.088646)
		(layer "F.Cu")
		(net "M_A_CPU0_SB_DQ<27>")
	)
	(segment
		(start 310.053482 -201.991722)
		(end 310.088026 -202.026266)
		(width 0.1016)
		(layer "F.Cu")
		(net "M_A_CPU0_SB_DQ<27>")
	)
	(segment
		(start 335.14538 -221.669864)
		(end 335.176876 -221.638368)
		(width 0.088646)
		(layer "F.Cu")
		(net "M_A_CPU0_SB_DQ<27>")
	)
	(segment
		(start 307.76291 -202.007724)
		(end 307.786278 -202.007724)
		(width 0.101854)
		(layer "F.Cu")
		(net "M_A_CPU0_SB_DQ<27>")
	)
	(segment
		(start 305.443382 -201.56678)
		(end 307.126132 -201.56678)
		(width 0.20066)
		(layer "F.Cu")
		(net "M_A_CPU0_SB_DQ<27>")
	)
	(segment
		(start 321.997578 -203.289408)
		(end 321.778122 -203.069952)
		(width 0.20066)
		(layer "F.Cu")
		(net "M_A_CPU0_SB_DQ<27>")
	)
	(segment
		(start 311.286652 -201.48677)
		(end 311.708546 -201.908664)
		(width 0.20066)
		(layer "F.Cu")
		(net "M_A_CPU0_SB_DQ<27>")
	)
	(segment
		(start 334.87868 -221.386908)
		(end 334.761332 -221.504256)
		(width 0.088646)
		(layer "F.Cu")
		(net "M_A_CPU0_SB_DQ<27>")
	)
	(segment
		(start 323.713602 -203.869036)
		(end 323.286882 -204.295248)
		(width 0.20066)
		(layer "F.Cu")
		(net "M_A_CPU0_SB_DQ<27>")
	)
	(segment
		(start 307.786278 -202.007724)
		(end 307.80228 -201.991722)
		(width 0.101854)
		(layer "F.Cu")
		(net "M_A_CPU0_SB_DQ<27>")
	)
	(segment
		(start 321.778122 -203.069952)
		(end 321.778122 -202.786488)
		(width 0.20066)
		(layer "F.Cu")
		(net "M_A_CPU0_SB_DQ<27>")
	)
	(segment
		(start 333.96301 -221.23527)
		(end 333.852774 -221.345506)
		(width 0.088646)
		(layer "F.Cu")
		(net "M_A_CPU0_SB_DQ<27>")
	)
	(arc
		(start 332.884526 -221.419166)
		(mid 332.843614 -221.43619)
		(end 332.79969 -221.442026)
		(width 0.088646)
		(layer "F.Cu")
		(net "M_A_CPU0_SB_DQ<27>")
	)
	(arc
		(start 334.381856 -221.346268)
		(mid 334.320052 -221.317697)
		(end 334.254094 -221.300802)
		(width 0.088646)
		(layer "F.Cu")
		(net "M_A_CPU0_SB_DQ<27>")
	)
	(arc
		(start 333.452978 -221.345506)
		(mid 333.23265 -221.286543)
		(end 333.012288 -221.345506)
		(width 0.088646)
		(layer "F.Cu")
		(net "M_A_CPU0_SB_DQ<27>")
	)
	(segment
		(start 329.645772 -219.646754)
		(end 329.645772 -214.38743)
		(width 0.1016)
		(layer "F.Cu")
		(net "M_A_CPU0_SB_DQ<26>")
	)
	(segment
		(start 327.447402 -209.12836)
		(end 327.228454 -208.909412)
		(width 0.20066)
		(layer "F.Cu")
		(net "M_A_CPU0_SB_DQ<26>")
	)
	(segment
		(start 332.802738 -221.942152)
		(end 332.552294 -221.928182)
		(width 0.088646)
		(layer "F.Cu")
		(net "M_A_CPU0_SB_DQ<26>")
	)
	(segment
		(start 325.228712 -208.32953)
		(end 319.750948 -202.851766)
		(width 0.20066)
		(layer "F.Cu")
		(net "M_A_CPU0_SB_DQ<26>")
	)
	(segment
		(start 314.84316 -203.173838)
		(end 314.375292 -203.266802)
		(width 0.20066)
		(layer "F.Cu")
		(net "M_A_CPU0_SB_DQ<26>")
	)
	(segment
		(start 329.452478 -214.194136)
		(end 329.452478 -214.033862)
		(width 0.1016)
		(layer "F.Cu")
		(net "M_A_CPU0_SB_DQ<26>")
	)
	(segment
		(start 314.375292 -203.266802)
		(end 312.987182 -203.266802)
		(width 0.20066)
		(layer "F.Cu")
		(net "M_A_CPU0_SB_DQ<26>")
	)
	(segment
		(start 328.949558 -210.927696)
		(end 328.530204 -211.34705)
		(width 0.20066)
		(layer "F.Cu")
		(net "M_A_CPU0_SB_DQ<26>")
	)
	(segment
		(start 333.914496 -221.960186)
		(end 333.82458 -221.87027)
		(width 0.088646)
		(layer "F.Cu")
		(net "M_A_CPU0_SB_DQ<26>")
	)
	(segment
		(start 310.452516 -203.691744)
		(end 310.586882 -203.557378)
		(width 0.20066)
		(layer "F.Cu")
		(net "M_A_CPU0_SB_DQ<26>")
	)
	(segment
		(start 327.021444 -209.83829)
		(end 327.447402 -209.412332)
		(width 0.20066)
		(layer "F.Cu")
		(net "M_A_CPU0_SB_DQ<26>")
	)
	(segment
		(start 328.234294 -209.915252)
		(end 327.950322 -209.915252)
		(width 0.20066)
		(layer "F.Cu")
		(net "M_A_CPU0_SB_DQ<26>")
	)
	(segment
		(start 331.683868 -221.68485)
		(end 329.645772 -219.646754)
		(width 0.1016)
		(layer "F.Cu")
		(net "M_A_CPU0_SB_DQ<26>")
	)
	(segment
		(start 327.950322 -209.915252)
		(end 327.524364 -210.34121)
		(width 0.20066)
		(layer "F.Cu")
		(net "M_A_CPU0_SB_DQ<26>")
	)
	(segment
		(start 329.645772 -214.38743)
		(end 329.452478 -214.194136)
		(width 0.1016)
		(layer "F.Cu")
		(net "M_A_CPU0_SB_DQ<26>")
	)
	(segment
		(start 329.033124 -212.133942)
		(end 329.033124 -211.84997)
		(width 0.20066)
		(layer "F.Cu")
		(net "M_A_CPU0_SB_DQ<26>")
	)
	(segment
		(start 310.586882 -203.557378)
		(end 310.586882 -203.20762)
		(width 0.20066)
		(layer "F.Cu")
		(net "M_A_CPU0_SB_DQ<26>")
	)
	(segment
		(start 326.222614 -207.903572)
		(end 325.938642 -207.903572)
		(width 0.20066)
		(layer "F.Cu")
		(net "M_A_CPU0_SB_DQ<26>")
	)
	(segment
		(start 333.914496 -222.087948)
		(end 333.914496 -221.960186)
		(width 0.088646)
		(layer "F.Cu")
		(net "M_A_CPU0_SB_DQ<26>")
	)
	(segment
		(start 315.333888 -202.851766)
		(end 315.053726 -203.131928)
		(width 0.20066)
		(layer "F.Cu")
		(net "M_A_CPU0_SB_DQ<26>")
	)
	(segment
		(start 329.452478 -211.146644)
		(end 329.23353 -210.927696)
		(width 0.20066)
		(layer "F.Cu")
		(net "M_A_CPU0_SB_DQ<26>")
	)
	(segment
		(start 328.530204 -211.34705)
		(end 328.246232 -211.34705)
		(width 0.20066)
		(layer "F.Cu")
		(net "M_A_CPU0_SB_DQ<26>")
	)
	(segment
		(start 305.443382 -203.266802)
		(end 307.118766 -203.266802)
		(width 0.20066)
		(layer "F.Cu")
		(net "M_A_CPU0_SB_DQ<26>")
	)
	(segment
		(start 310.586882 -203.20762)
		(end 310.71439 -203.080112)
		(width 0.20066)
		(layer "F.Cu")
		(net "M_A_CPU0_SB_DQ<26>")
	)
	(segment
		(start 328.453242 -210.1342)
		(end 328.234294 -209.915252)
		(width 0.20066)
		(layer "F.Cu")
		(net "M_A_CPU0_SB_DQ<26>")
	)
	(segment
		(start 327.228454 -208.909412)
		(end 326.944482 -208.909412)
		(width 0.20066)
		(layer "F.Cu")
		(net "M_A_CPU0_SB_DQ<26>")
	)
	(segment
		(start 307.77815 -203.691744)
		(end 307.82768 -203.691744)
		(width 0.101854)
		(layer "F.Cu")
		(net "M_A_CPU0_SB_DQ<26>")
	)
	(segment
		(start 326.441562 -208.406492)
		(end 326.441562 -208.12252)
		(width 0.20066)
		(layer "F.Cu")
		(net "M_A_CPU0_SB_DQ<26>")
	)
	(segment
		(start 328.027284 -211.128102)
		(end 328.027284 -210.84413)
		(width 0.20066)
		(layer "F.Cu")
		(net "M_A_CPU0_SB_DQ<26>")
	)
	(segment
		(start 326.441562 -208.12252)
		(end 326.222614 -207.903572)
		(width 0.20066)
		(layer "F.Cu")
		(net "M_A_CPU0_SB_DQ<26>")
	)
	(segment
		(start 329.23353 -210.927696)
		(end 328.949558 -210.927696)
		(width 0.20066)
		(layer "F.Cu")
		(net "M_A_CPU0_SB_DQ<26>")
	)
	(segment
		(start 327.240392 -210.34121)
		(end 327.021444 -210.122262)
		(width 0.20066)
		(layer "F.Cu")
		(net "M_A_CPU0_SB_DQ<26>")
	)
	(segment
		(start 326.518524 -209.33537)
		(end 326.234552 -209.33537)
		(width 0.20066)
		(layer "F.Cu")
		(net "M_A_CPU0_SB_DQ<26>")
	)
	(segment
		(start 329.033124 -211.84997)
		(end 329.452478 -211.430616)
		(width 0.20066)
		(layer "F.Cu")
		(net "M_A_CPU0_SB_DQ<26>")
	)
	(segment
		(start 310.03748 -203.691744)
		(end 310.088026 -203.691744)
		(width 0.101854)
		(layer "F.Cu")
		(net "M_A_CPU0_SB_DQ<26>")
	)
	(segment
		(start 311.087008 -203.080112)
		(end 311.273698 -203.266802)
		(width 0.20066)
		(layer "F.Cu")
		(net "M_A_CPU0_SB_DQ<26>")
	)
	(segment
		(start 331.874622 -221.875604)
		(end 331.683868 -221.68485)
		(width 0.088646)
		(layer "F.Cu")
		(net "M_A_CPU0_SB_DQ<26>")
	)
	(segment
		(start 327.021444 -210.122262)
		(end 327.021444 -209.83829)
		(width 0.20066)
		(layer "F.Cu")
		(net "M_A_CPU0_SB_DQ<26>")
	)
	(segment
		(start 333.82458 -221.87027)
		(end 333.697072 -221.87027)
		(width 0.088646)
		(layer "F.Cu")
		(net "M_A_CPU0_SB_DQ<26>")
	)
	(segment
		(start 326.015604 -208.83245)
		(end 326.441562 -208.406492)
		(width 0.20066)
		(layer "F.Cu")
		(net "M_A_CPU0_SB_DQ<26>")
	)
	(segment
		(start 333.092298 -222.009716)
		(end 332.802738 -221.942152)
		(width 0.088646)
		(layer "F.Cu")
		(net "M_A_CPU0_SB_DQ<26>")
	)
	(segment
		(start 332.552294 -221.928182)
		(end 332.09865 -221.993714)
		(width 0.088646)
		(layer "F.Cu")
		(net "M_A_CPU0_SB_DQ<26>")
	)
	(segment
		(start 329.452478 -211.430616)
		(end 329.452478 -211.146644)
		(width 0.20066)
		(layer "F.Cu")
		(net "M_A_CPU0_SB_DQ<26>")
	)
	(segment
		(start 307.76291 -203.706984)
		(end 307.77815 -203.691744)
		(width 0.101854)
		(layer "F.Cu")
		(net "M_A_CPU0_SB_DQ<26>")
	)
	(segment
		(start 326.015604 -209.116422)
		(end 326.015604 -208.83245)
		(width 0.20066)
		(layer "F.Cu")
		(net "M_A_CPU0_SB_DQ<26>")
	)
	(segment
		(start 319.750948 -202.851766)
		(end 315.333888 -202.851766)
		(width 0.20066)
		(layer "F.Cu")
		(net "M_A_CPU0_SB_DQ<26>")
	)
	(segment
		(start 328.246232 -211.34705)
		(end 328.027284 -211.128102)
		(width 0.20066)
		(layer "F.Cu")
		(net "M_A_CPU0_SB_DQ<26>")
	)
	(segment
		(start 325.512684 -208.32953)
		(end 325.228712 -208.32953)
		(width 0.20066)
		(layer "F.Cu")
		(net "M_A_CPU0_SB_DQ<26>")
	)
	(segment
		(start 307.562504 -203.71054)
		(end 307.759354 -203.71054)
		(width 0.20066)
		(layer "F.Cu")
		(net "M_A_CPU0_SB_DQ<26>")
	)
	(segment
		(start 325.938642 -207.903572)
		(end 325.512684 -208.32953)
		(width 0.20066)
		(layer "F.Cu")
		(net "M_A_CPU0_SB_DQ<26>")
	)
	(segment
		(start 329.452478 -214.033862)
		(end 329.452478 -212.553296)
		(width 0.20066)
		(layer "F.Cu")
		(net "M_A_CPU0_SB_DQ<26>")
	)
	(segment
		(start 307.759354 -203.71054)
		(end 307.76291 -203.706984)
		(width 0.20066)
		(layer "F.Cu")
		(net "M_A_CPU0_SB_DQ<26>")
	)
	(segment
		(start 333.697072 -221.87027)
		(end 333.57439 -221.992952)
		(width 0.088646)
		(layer "F.Cu")
		(net "M_A_CPU0_SB_DQ<26>")
	)
	(segment
		(start 333.57439 -222.039434)
		(end 333.482696 -222.131128)
		(width 0.088646)
		(layer "F.Cu")
		(net "M_A_CPU0_SB_DQ<26>")
	)
	(segment
		(start 328.453242 -210.418172)
		(end 328.453242 -210.1342)
		(width 0.20066)
		(layer "F.Cu")
		(net "M_A_CPU0_SB_DQ<26>")
	)
	(segment
		(start 315.053726 -203.131928)
		(end 314.84316 -203.173838)
		(width 0.20066)
		(layer "F.Cu")
		(net "M_A_CPU0_SB_DQ<26>")
	)
	(segment
		(start 334.49768 -222.30715)
		(end 334.133698 -222.30715)
		(width 0.088646)
		(layer "F.Cu")
		(net "M_A_CPU0_SB_DQ<26>")
	)
	(segment
		(start 334.675734 -222.48368)
		(end 334.49768 -222.30715)
		(width 0.088646)
		(layer "F.Cu")
		(net "M_A_CPU0_SB_DQ<26>")
	)
	(segment
		(start 334.133698 -222.30715)
		(end 333.914496 -222.087948)
		(width 0.088646)
		(layer "F.Cu")
		(net "M_A_CPU0_SB_DQ<26>")
	)
	(segment
		(start 327.447402 -209.412332)
		(end 327.447402 -209.12836)
		(width 0.20066)
		(layer "F.Cu")
		(net "M_A_CPU0_SB_DQ<26>")
	)
	(segment
		(start 307.82768 -203.691744)
		(end 310.03748 -203.691744)
		(width 0.1016)
		(layer "F.Cu")
		(net "M_A_CPU0_SB_DQ<26>")
	)
	(segment
		(start 333.482696 -222.131128)
		(end 333.326486 -222.131128)
		(width 0.088646)
		(layer "F.Cu")
		(net "M_A_CPU0_SB_DQ<26>")
	)
	(segment
		(start 328.027284 -210.84413)
		(end 328.453242 -210.418172)
		(width 0.20066)
		(layer "F.Cu")
		(net "M_A_CPU0_SB_DQ<26>")
	)
	(segment
		(start 329.452478 -212.553296)
		(end 329.033124 -212.133942)
		(width 0.20066)
		(layer "F.Cu")
		(net "M_A_CPU0_SB_DQ<26>")
	)
	(segment
		(start 327.524364 -210.34121)
		(end 327.240392 -210.34121)
		(width 0.20066)
		(layer "F.Cu")
		(net "M_A_CPU0_SB_DQ<26>")
	)
	(segment
		(start 333.57439 -221.992952)
		(end 333.57439 -222.039434)
		(width 0.088646)
		(layer "F.Cu")
		(net "M_A_CPU0_SB_DQ<26>")
	)
	(segment
		(start 326.944482 -208.909412)
		(end 326.518524 -209.33537)
		(width 0.20066)
		(layer "F.Cu")
		(net "M_A_CPU0_SB_DQ<26>")
	)
	(segment
		(start 326.234552 -209.33537)
		(end 326.015604 -209.116422)
		(width 0.20066)
		(layer "F.Cu")
		(net "M_A_CPU0_SB_DQ<26>")
	)
	(segment
		(start 310.71439 -203.080112)
		(end 311.087008 -203.080112)
		(width 0.20066)
		(layer "F.Cu")
		(net "M_A_CPU0_SB_DQ<26>")
	)
	(segment
		(start 310.088026 -203.691744)
		(end 310.452516 -203.691744)
		(width 0.20066)
		(layer "F.Cu")
		(net "M_A_CPU0_SB_DQ<26>")
	)
	(segment
		(start 311.273698 -203.266802)
		(end 312.987182 -203.266802)
		(width 0.20066)
		(layer "F.Cu")
		(net "M_A_CPU0_SB_DQ<26>")
	)
	(segment
		(start 307.118766 -203.266802)
		(end 307.562504 -203.71054)
		(width 0.20066)
		(layer "F.Cu")
		(net "M_A_CPU0_SB_DQ<26>")
	)
	(segment
		(start 333.282036 -222.11919)
		(end 333.092298 -222.009716)
		(width 0.088646)
		(layer "F.Cu")
		(net "M_A_CPU0_SB_DQ<26>")
	)
	(arc
		(start 332.09865 -221.993714)
		(mid 331.977713 -221.951582)
		(end 331.874622 -221.875604)
		(width 0.088646)
		(layer "F.Cu")
		(net "M_A_CPU0_SB_DQ<26>")
	)
	(arc
		(start 333.326486 -222.131128)
		(mid 333.303475 -222.128089)
		(end 333.282036 -222.11919)
		(width 0.088646)
		(layer "F.Cu")
		(net "M_A_CPU0_SB_DQ<26>")
	)
	(segment
		(start 314.15228 -202.861164)
		(end 314.131198 -202.861164)
		(width 0.101854)
		(layer "F.Cu")
		(net "M_A_CPU0_SB_DQ<25>")
	)
	(segment
		(start 324.940168 -206.958184)
		(end 324.940168 -206.674212)
		(width 0.20066)
		(layer "F.Cu")
		(net "M_A_CPU0_SB_DQ<25>")
	)
	(segment
		(start 323.955918 -205.930754)
		(end 323.955918 -205.646782)
		(width 0.20066)
		(layer "F.Cu")
		(net "M_A_CPU0_SB_DQ<25>")
	)
	(segment
		(start 309.974742 -202.416664)
		(end 308.887114 -202.416664)
		(width 0.20066)
		(layer "F.Cu")
		(net "M_A_CPU0_SB_DQ<25>")
	)
	(segment
		(start 303.686718 -201.982832)
		(end 304.319178 -201.982832)
		(width 0.20066)
		(layer "F.Cu")
		(net "M_A_CPU0_SB_DQ<25>")
	)
	(segment
		(start 311.91708 -202.859132)
		(end 311.732676 -202.859132)
		(width 0.20066)
		(layer "F.Cu")
		(net "M_A_CPU0_SB_DQ<25>")
	)
	(segment
		(start 323.768212 -204.828648)
		(end 323.342254 -205.254606)
		(width 0.20066)
		(layer "F.Cu")
		(net "M_A_CPU0_SB_DQ<25>")
	)
	(segment
		(start 325.443088 -207.177132)
		(end 325.159116 -207.177132)
		(width 0.20066)
		(layer "F.Cu")
		(net "M_A_CPU0_SB_DQ<25>")
	)
	(segment
		(start 314.131198 -202.861164)
		(end 314.11164 -202.841606)
		(width 0.101854)
		(layer "F.Cu")
		(net "M_A_CPU0_SB_DQ<25>")
	)
	(segment
		(start 324.052184 -204.828648)
		(end 323.768212 -204.828648)
		(width 0.20066)
		(layer "F.Cu")
		(net "M_A_CPU0_SB_DQ<25>")
	)
	(segment
		(start 323.955918 -205.646782)
		(end 324.271132 -205.331568)
		(width 0.20066)
		(layer "F.Cu")
		(net "M_A_CPU0_SB_DQ<25>")
	)
	(segment
		(start 330.09205 -214.033608)
		(end 330.09205 -210.868514)
		(width 0.20066)
		(layer "F.Cu")
		(net "M_A_CPU0_SB_DQ<25>")
	)
	(segment
		(start 329.950572 -219.520262)
		(end 329.950572 -214.408258)
		(width 0.1016)
		(layer "F.Cu")
		(net "M_A_CPU0_SB_DQ<25>")
	)
	(segment
		(start 331.899514 -221.469204)
		(end 329.950572 -219.520262)
		(width 0.1016)
		(layer "F.Cu")
		(net "M_A_CPU0_SB_DQ<25>")
	)
	(segment
		(start 324.774052 -205.834488)
		(end 324.458838 -206.149702)
		(width 0.20066)
		(layer "F.Cu")
		(net "M_A_CPU0_SB_DQ<25>")
	)
	(segment
		(start 325.276972 -206.337408)
		(end 325.276972 -206.053436)
		(width 0.20066)
		(layer "F.Cu")
		(net "M_A_CPU0_SB_DQ<25>")
	)
	(segment
		(start 306.848002 -201.991722)
		(end 307.272944 -202.416664)
		(width 0.20066)
		(layer "F.Cu")
		(net "M_A_CPU0_SB_DQ<25>")
	)
	(segment
		(start 324.458838 -206.149702)
		(end 324.174866 -206.149702)
		(width 0.20066)
		(layer "F.Cu")
		(net "M_A_CPU0_SB_DQ<25>")
	)
	(segment
		(start 306.58689 -201.991722)
		(end 306.644294 -201.991722)
		(width 0.101854)
		(layer "F.Cu")
		(net "M_A_CPU0_SB_DQ<25>")
	)
	(segment
		(start 307.272944 -202.416664)
		(end 308.887114 -202.416664)
		(width 0.20066)
		(layer "F.Cu")
		(net "M_A_CPU0_SB_DQ<25>")
	)
	(segment
		(start 324.940168 -206.674212)
		(end 325.276972 -206.337408)
		(width 0.20066)
		(layer "F.Cu")
		(net "M_A_CPU0_SB_DQ<25>")
	)
	(segment
		(start 333.26578 -221.669864)
		(end 332.10119 -221.67088)
		(width 0.088646)
		(layer "F.Cu")
		(net "M_A_CPU0_SB_DQ<25>")
	)
	(segment
		(start 303.295812 -202.668378)
		(end 303.523396 -202.440794)
		(width 0.20066)
		(layer "F.Cu")
		(net "M_A_CPU0_SB_DQ<25>")
	)
	(segment
		(start 302.653446 -202.416664)
		(end 302.90516 -202.668378)
		(width 0.20066)
		(layer "F.Cu")
		(net "M_A_CPU0_SB_DQ<25>")
	)
	(segment
		(start 311.732676 -202.859132)
		(end 311.242202 -202.693016)
		(width 0.20066)
		(layer "F.Cu")
		(net "M_A_CPU0_SB_DQ<25>")
	)
	(segment
		(start 320.005456 -202.20178)
		(end 315.062616 -202.20178)
		(width 0.20066)
		(layer "F.Cu")
		(net "M_A_CPU0_SB_DQ<25>")
	)
	(segment
		(start 303.523396 -202.146154)
		(end 303.686718 -201.982832)
		(width 0.20066)
		(layer "F.Cu")
		(net "M_A_CPU0_SB_DQ<25>")
	)
	(segment
		(start 323.058282 -205.254606)
		(end 320.005456 -202.20178)
		(width 0.20066)
		(layer "F.Cu")
		(net "M_A_CPU0_SB_DQ<25>")
	)
	(segment
		(start 332.10119 -221.67088)
		(end 331.899514 -221.469204)
		(width 0.088646)
		(layer "F.Cu")
		(net "M_A_CPU0_SB_DQ<25>")
	)
	(segment
		(start 325.058024 -205.834488)
		(end 324.774052 -205.834488)
		(width 0.20066)
		(layer "F.Cu")
		(net "M_A_CPU0_SB_DQ<25>")
	)
	(segment
		(start 314.750958 -202.391264)
		(end 314.281058 -202.861164)
		(width 0.20066)
		(layer "F.Cu")
		(net "M_A_CPU0_SB_DQ<25>")
	)
	(segment
		(start 303.523396 -202.440794)
		(end 303.523396 -202.146154)
		(width 0.20066)
		(layer "F.Cu")
		(net "M_A_CPU0_SB_DQ<25>")
	)
	(segment
		(start 314.11164 -202.841606)
		(end 312.116216 -202.841606)
		(width 0.1016)
		(layer "F.Cu")
		(net "M_A_CPU0_SB_DQ<25>")
	)
	(segment
		(start 325.276972 -206.053436)
		(end 325.058024 -205.834488)
		(width 0.20066)
		(layer "F.Cu")
		(net "M_A_CPU0_SB_DQ<25>")
	)
	(segment
		(start 306.644294 -201.991722)
		(end 306.848002 -201.991722)
		(width 0.20066)
		(layer "F.Cu")
		(net "M_A_CPU0_SB_DQ<25>")
	)
	(segment
		(start 324.271132 -205.047596)
		(end 324.052184 -204.828648)
		(width 0.20066)
		(layer "F.Cu")
		(net "M_A_CPU0_SB_DQ<25>")
	)
	(segment
		(start 324.271132 -205.331568)
		(end 324.271132 -205.047596)
		(width 0.20066)
		(layer "F.Cu")
		(net "M_A_CPU0_SB_DQ<25>")
	)
	(segment
		(start 330.09205 -214.26678)
		(end 330.09205 -214.033608)
		(width 0.1016)
		(layer "F.Cu")
		(net "M_A_CPU0_SB_DQ<25>")
	)
	(segment
		(start 304.319178 -201.982832)
		(end 304.362358 -201.982832)
		(width 0.101854)
		(layer "F.Cu")
		(net "M_A_CPU0_SB_DQ<25>")
	)
	(segment
		(start 312.116216 -202.841606)
		(end 312.059574 -202.859132)
		(width 0.1016)
		(layer "F.Cu")
		(net "M_A_CPU0_SB_DQ<25>")
	)
	(segment
		(start 311.242202 -202.693016)
		(end 309.974742 -202.416664)
		(width 0.20066)
		(layer "F.Cu")
		(net "M_A_CPU0_SB_DQ<25>")
	)
	(segment
		(start 315.062616 -202.20178)
		(end 314.873132 -202.391264)
		(width 0.20066)
		(layer "F.Cu")
		(net "M_A_CPU0_SB_DQ<25>")
	)
	(segment
		(start 326.063864 -206.840328)
		(end 325.779892 -206.840328)
		(width 0.20066)
		(layer "F.Cu")
		(net "M_A_CPU0_SB_DQ<25>")
	)
	(segment
		(start 329.950572 -214.408258)
		(end 330.09205 -214.26678)
		(width 0.1016)
		(layer "F.Cu")
		(net "M_A_CPU0_SB_DQ<25>")
	)
	(segment
		(start 302.90516 -202.668378)
		(end 303.295812 -202.668378)
		(width 0.20066)
		(layer "F.Cu")
		(net "M_A_CPU0_SB_DQ<25>")
	)
	(segment
		(start 314.281058 -202.861164)
		(end 314.15228 -202.861164)
		(width 0.20066)
		(layer "F.Cu")
		(net "M_A_CPU0_SB_DQ<25>")
	)
	(segment
		(start 323.342254 -205.254606)
		(end 323.058282 -205.254606)
		(width 0.20066)
		(layer "F.Cu")
		(net "M_A_CPU0_SB_DQ<25>")
	)
	(segment
		(start 324.174866 -206.149702)
		(end 323.955918 -205.930754)
		(width 0.20066)
		(layer "F.Cu")
		(net "M_A_CPU0_SB_DQ<25>")
	)
	(segment
		(start 314.873132 -202.391264)
		(end 314.750958 -202.391264)
		(width 0.20066)
		(layer "F.Cu")
		(net "M_A_CPU0_SB_DQ<25>")
	)
	(segment
		(start 301.343314 -202.416664)
		(end 302.653446 -202.416664)
		(width 0.20066)
		(layer "F.Cu")
		(net "M_A_CPU0_SB_DQ<25>")
	)
	(segment
		(start 304.362358 -201.982832)
		(end 304.391314 -201.991722)
		(width 0.1016)
		(layer "F.Cu")
		(net "M_A_CPU0_SB_DQ<25>")
	)
	(segment
		(start 325.779892 -206.840328)
		(end 325.443088 -207.177132)
		(width 0.20066)
		(layer "F.Cu")
		(net "M_A_CPU0_SB_DQ<25>")
	)
	(segment
		(start 312.059574 -202.859132)
		(end 311.91708 -202.859132)
		(width 0.101854)
		(layer "F.Cu")
		(net "M_A_CPU0_SB_DQ<25>")
	)
	(segment
		(start 325.159116 -207.177132)
		(end 324.940168 -206.958184)
		(width 0.20066)
		(layer "F.Cu")
		(net "M_A_CPU0_SB_DQ<25>")
	)
	(segment
		(start 304.391314 -201.991722)
		(end 306.58689 -201.991722)
		(width 0.1016)
		(layer "F.Cu")
		(net "M_A_CPU0_SB_DQ<25>")
	)
	(segment
		(start 330.09205 -210.868514)
		(end 326.063864 -206.840328)
		(width 0.20066)
		(layer "F.Cu")
		(net "M_A_CPU0_SB_DQ<25>")
	)
	(segment
		(start 314.10148 -203.679806)
		(end 314.072778 -203.679806)
		(width 0.101854)
		(layer "F.Cu")
		(net "M_A_CPU0_SB_DQ<24>")
	)
	(segment
		(start 304.357278 -203.691744)
		(end 306.289202 -203.691744)
		(width 0.1016)
		(layer "F.Cu")
		(net "M_A_CPU0_SB_DQ<24>")
	)
	(segment
		(start 311.89168 -203.67625)
		(end 311.201308 -203.67625)
		(width 0.20066)
		(layer "F.Cu")
		(net "M_A_CPU0_SB_DQ<24>")
	)
	(segment
		(start 329.340972 -216.006172)
		(end 329.121008 -215.786208)
		(width 0.1016)
		(layer "F.Cu")
		(net "M_A_CPU0_SB_DQ<24>")
	)
	(segment
		(start 303.369726 -204.377798)
		(end 303.587404 -204.16012)
		(width 0.20066)
		(layer "F.Cu")
		(net "M_A_CPU0_SB_DQ<24>")
	)
	(segment
		(start 318.172084 -204.265784)
		(end 317.971424 -204.466444)
		(width 0.20066)
		(layer "F.Cu")
		(net "M_A_CPU0_SB_DQ<24>")
	)
	(segment
		(start 331.873352 -222.305626)
		(end 331.468222 -221.900496)
		(width 0.088646)
		(layer "F.Cu")
		(net "M_A_CPU0_SB_DQ<24>")
	)
	(segment
		(start 306.289202 -203.691744)
		(end 306.644294 -203.691744)
		(width 0.101854)
		(layer "F.Cu")
		(net "M_A_CPU0_SB_DQ<24>")
	)
	(segment
		(start 312.12536 -203.691744)
		(end 312.08091 -203.67625)
		(width 0.1016)
		(layer "F.Cu")
		(net "M_A_CPU0_SB_DQ<24>")
	)
	(segment
		(start 316.749684 -203.708508)
		(end 316.749684 -204.265784)
		(width 0.20066)
		(layer "F.Cu")
		(net "M_A_CPU0_SB_DQ<24>")
	)
	(segment
		(start 318.883284 -204.265784)
		(end 318.883284 -203.708508)
		(width 0.20066)
		(layer "F.Cu")
		(net "M_A_CPU0_SB_DQ<24>")
	)
	(segment
		(start 306.848002 -203.691744)
		(end 307.272944 -204.116686)
		(width 0.20066)
		(layer "F.Cu")
		(net "M_A_CPU0_SB_DQ<24>")
	)
	(segment
		(start 329.121008 -215.247728)
		(end 329.340972 -215.027764)
		(width 0.1016)
		(layer "F.Cu")
		(net "M_A_CPU0_SB_DQ<24>")
	)
	(segment
		(start 318.172084 -203.708508)
		(end 318.172084 -204.265784)
		(width 0.20066)
		(layer "F.Cu")
		(net "M_A_CPU0_SB_DQ<24>")
	)
	(segment
		(start 310.760872 -204.116686)
		(end 308.887114 -204.116686)
		(width 0.20066)
		(layer "F.Cu")
		(net "M_A_CPU0_SB_DQ<24>")
	)
	(segment
		(start 316.749684 -204.265784)
		(end 316.549024 -204.466444)
		(width 0.20066)
		(layer "F.Cu")
		(net "M_A_CPU0_SB_DQ<24>")
	)
	(segment
		(start 328.830178 -214.315802)
		(end 328.812906 -214.29853)
		(width 0.1016)
		(layer "F.Cu")
		(net "M_A_CPU0_SB_DQ<24>")
	)
	(segment
		(start 314.06084 -203.691744)
		(end 312.12536 -203.691744)
		(width 0.1016)
		(layer "F.Cu")
		(net "M_A_CPU0_SB_DQ<24>")
	)
	(segment
		(start 314.510928 -203.81849)
		(end 314.17895 -203.679806)
		(width 0.20066)
		(layer "F.Cu")
		(net "M_A_CPU0_SB_DQ<24>")
	)
	(segment
		(start 316.549024 -204.466444)
		(end 316.239144 -204.466444)
		(width 0.20066)
		(layer "F.Cu")
		(net "M_A_CPU0_SB_DQ<24>")
	)
	(segment
		(start 320.07048 -204.076046)
		(end 319.784222 -204.076046)
		(width 0.20066)
		(layer "F.Cu")
		(net "M_A_CPU0_SB_DQ<24>")
	)
	(segment
		(start 329.121008 -215.786208)
		(end 329.121008 -215.247728)
		(width 0.1016)
		(layer "F.Cu")
		(net "M_A_CPU0_SB_DQ<24>")
	)
	(segment
		(start 329.340972 -214.82685)
		(end 328.830178 -214.316056)
		(width 0.1016)
		(layer "F.Cu")
		(net "M_A_CPU0_SB_DQ<24>")
	)
	(segment
		(start 314.072778 -203.679806)
		(end 314.06084 -203.691744)
		(width 0.101854)
		(layer "F.Cu")
		(net "M_A_CPU0_SB_DQ<24>")
	)
	(segment
		(start 317.661544 -204.466444)
		(end 317.460884 -204.265784)
		(width 0.20066)
		(layer "F.Cu")
		(net "M_A_CPU0_SB_DQ<24>")
	)
	(segment
		(start 315.837824 -203.507848)
		(end 315.590682 -203.507848)
		(width 0.20066)
		(layer "F.Cu")
		(net "M_A_CPU0_SB_DQ<24>")
	)
	(segment
		(start 328.812906 -214.29853)
		(end 328.812906 -214.033862)
		(width 0.1016)
		(layer "F.Cu")
		(net "M_A_CPU0_SB_DQ<24>")
	)
	(segment
		(start 318.372744 -203.507848)
		(end 318.172084 -203.708508)
		(width 0.20066)
		(layer "F.Cu")
		(net "M_A_CPU0_SB_DQ<24>")
	)
	(segment
		(start 315.260228 -203.838302)
		(end 314.558172 -203.838302)
		(width 0.20066)
		(layer "F.Cu")
		(net "M_A_CPU0_SB_DQ<24>")
	)
	(segment
		(start 333.355442 -222.381826)
		(end 333.238348 -222.314262)
		(width 0.088646)
		(layer "F.Cu")
		(net "M_A_CPU0_SB_DQ<24>")
	)
	(segment
		(start 316.239144 -204.466444)
		(end 316.038484 -204.265784)
		(width 0.20066)
		(layer "F.Cu")
		(net "M_A_CPU0_SB_DQ<24>")
	)
	(segment
		(start 332.809596 -222.141542)
		(end 332.638908 -222.14713)
		(width 0.088646)
		(layer "F.Cu")
		(net "M_A_CPU0_SB_DQ<24>")
	)
	(segment
		(start 306.644294 -203.691744)
		(end 306.848002 -203.691744)
		(width 0.20066)
		(layer "F.Cu")
		(net "M_A_CPU0_SB_DQ<24>")
	)
	(segment
		(start 318.883284 -203.708508)
		(end 318.682624 -203.507848)
		(width 0.20066)
		(layer "F.Cu")
		(net "M_A_CPU0_SB_DQ<24>")
	)
	(segment
		(start 317.971424 -204.466444)
		(end 317.661544 -204.466444)
		(width 0.20066)
		(layer "F.Cu")
		(net "M_A_CPU0_SB_DQ<24>")
	)
	(segment
		(start 328.830178 -214.316056)
		(end 328.830178 -214.315802)
		(width 0.1016)
		(layer "F.Cu")
		(net "M_A_CPU0_SB_DQ<24>")
	)
	(segment
		(start 303.790604 -203.68006)
		(end 304.319178 -203.68006)
		(width 0.20066)
		(layer "F.Cu")
		(net "M_A_CPU0_SB_DQ<24>")
	)
	(segment
		(start 319.393824 -204.466444)
		(end 319.083944 -204.466444)
		(width 0.20066)
		(layer "F.Cu")
		(net "M_A_CPU0_SB_DQ<24>")
	)
	(segment
		(start 317.260224 -203.507848)
		(end 316.950344 -203.507848)
		(width 0.20066)
		(layer "F.Cu")
		(net "M_A_CPU0_SB_DQ<24>")
	)
	(segment
		(start 302.387254 -204.116686)
		(end 302.648366 -204.377798)
		(width 0.20066)
		(layer "F.Cu")
		(net "M_A_CPU0_SB_DQ<24>")
	)
	(segment
		(start 312.08091 -203.67625)
		(end 311.89168 -203.67625)
		(width 0.101854)
		(layer "F.Cu")
		(net "M_A_CPU0_SB_DQ<24>")
	)
	(segment
		(start 304.319178 -203.68006)
		(end 304.357278 -203.691744)
		(width 0.1016)
		(layer "F.Cu")
		(net "M_A_CPU0_SB_DQ<24>")
	)
	(segment
		(start 303.587404 -204.16012)
		(end 303.587404 -203.88326)
		(width 0.20066)
		(layer "F.Cu")
		(net "M_A_CPU0_SB_DQ<24>")
	)
	(segment
		(start 307.272944 -204.116686)
		(end 308.887114 -204.116686)
		(width 0.20066)
		(layer "F.Cu")
		(net "M_A_CPU0_SB_DQ<24>")
	)
	(segment
		(start 319.784222 -204.076046)
		(end 319.393824 -204.466444)
		(width 0.20066)
		(layer "F.Cu")
		(net "M_A_CPU0_SB_DQ<24>")
	)
	(segment
		(start 332.638908 -222.14713)
		(end 332.194916 -222.288354)
		(width 0.088646)
		(layer "F.Cu")
		(net "M_A_CPU0_SB_DQ<24>")
	)
	(segment
		(start 318.682624 -203.507848)
		(end 318.372744 -203.507848)
		(width 0.20066)
		(layer "F.Cu")
		(net "M_A_CPU0_SB_DQ<24>")
	)
	(segment
		(start 316.950344 -203.507848)
		(end 316.749684 -203.708508)
		(width 0.20066)
		(layer "F.Cu")
		(net "M_A_CPU0_SB_DQ<24>")
	)
	(segment
		(start 333.092552 -222.229934)
		(end 332.878684 -222.155258)
		(width 0.088646)
		(layer "F.Cu")
		(net "M_A_CPU0_SB_DQ<24>")
	)
	(segment
		(start 319.083944 -204.466444)
		(end 318.883284 -204.265784)
		(width 0.20066)
		(layer "F.Cu")
		(net "M_A_CPU0_SB_DQ<24>")
	)
	(segment
		(start 316.038484 -204.265784)
		(end 316.038484 -203.708508)
		(width 0.20066)
		(layer "F.Cu")
		(net "M_A_CPU0_SB_DQ<24>")
	)
	(segment
		(start 302.648366 -204.377798)
		(end 303.369726 -204.377798)
		(width 0.20066)
		(layer "F.Cu")
		(net "M_A_CPU0_SB_DQ<24>")
	)
	(segment
		(start 314.558172 -203.838302)
		(end 314.510928 -203.81849)
		(width 0.20066)
		(layer "F.Cu")
		(net "M_A_CPU0_SB_DQ<24>")
	)
	(segment
		(start 316.038484 -203.708508)
		(end 315.837824 -203.507848)
		(width 0.20066)
		(layer "F.Cu")
		(net "M_A_CPU0_SB_DQ<24>")
	)
	(segment
		(start 315.590682 -203.507848)
		(end 315.260228 -203.838302)
		(width 0.20066)
		(layer "F.Cu")
		(net "M_A_CPU0_SB_DQ<24>")
	)
	(segment
		(start 331.468222 -221.900496)
		(end 329.340972 -219.773246)
		(width 0.1016)
		(layer "F.Cu")
		(net "M_A_CPU0_SB_DQ<24>")
	)
	(segment
		(start 332.083664 -222.305626)
		(end 331.873352 -222.305626)
		(width 0.088646)
		(layer "F.Cu")
		(net "M_A_CPU0_SB_DQ<24>")
	)
	(segment
		(start 329.340972 -219.773246)
		(end 329.340972 -216.006172)
		(width 0.1016)
		(layer "F.Cu")
		(net "M_A_CPU0_SB_DQ<24>")
	)
	(segment
		(start 314.17895 -203.679806)
		(end 314.10148 -203.679806)
		(width 0.20066)
		(layer "F.Cu")
		(net "M_A_CPU0_SB_DQ<24>")
	)
	(segment
		(start 333.735934 -222.48368)
		(end 333.355442 -222.381826)
		(width 0.088646)
		(layer "F.Cu")
		(net "M_A_CPU0_SB_DQ<24>")
	)
	(segment
		(start 317.460884 -204.265784)
		(end 317.460884 -203.708508)
		(width 0.20066)
		(layer "F.Cu")
		(net "M_A_CPU0_SB_DQ<24>")
	)
	(segment
		(start 301.343314 -204.116686)
		(end 302.387254 -204.116686)
		(width 0.20066)
		(layer "F.Cu")
		(net "M_A_CPU0_SB_DQ<24>")
	)
	(segment
		(start 329.340972 -215.027764)
		(end 329.340972 -214.82685)
		(width 0.1016)
		(layer "F.Cu")
		(net "M_A_CPU0_SB_DQ<24>")
	)
	(segment
		(start 333.238348 -222.314262)
		(end 333.092552 -222.229934)
		(width 0.088646)
		(layer "F.Cu")
		(net "M_A_CPU0_SB_DQ<24>")
	)
	(segment
		(start 303.587404 -203.88326)
		(end 303.790604 -203.68006)
		(width 0.20066)
		(layer "F.Cu")
		(net "M_A_CPU0_SB_DQ<24>")
	)
	(segment
		(start 311.201308 -203.67625)
		(end 310.760872 -204.116686)
		(width 0.20066)
		(layer "F.Cu")
		(net "M_A_CPU0_SB_DQ<24>")
	)
	(segment
		(start 317.460884 -203.708508)
		(end 317.260224 -203.507848)
		(width 0.20066)
		(layer "F.Cu")
		(net "M_A_CPU0_SB_DQ<24>")
	)
	(segment
		(start 332.878684 -222.155258)
		(end 332.809596 -222.141542)
		(width 0.088646)
		(layer "F.Cu")
		(net "M_A_CPU0_SB_DQ<24>")
	)
	(segment
		(start 328.812906 -214.033862)
		(end 328.812906 -212.818472)
		(width 0.20066)
		(layer "F.Cu")
		(net "M_A_CPU0_SB_DQ<24>")
	)
	(segment
		(start 328.812906 -212.818472)
		(end 320.07048 -204.076046)
		(width 0.20066)
		(layer "F.Cu")
		(net "M_A_CPU0_SB_DQ<24>")
	)
	(arc
		(start 332.194916 -222.288354)
		(mid 332.139954 -222.301275)
		(end 332.083664 -222.305626)
		(width 0.088646)
		(layer "F.Cu")
		(net "M_A_CPU0_SB_DQ<24>")
	)
	(segment
		(start 329.630532 -226.235768)
		(end 329.630532 -224.096834)
		(width 0.1016)
		(layer "F.Cu")
		(net "M_A_CPU0_SB_DQ<23>")
	)
	(segment
		(start 310.03748 -205.391512)
		(end 310.088026 -205.391512)
		(width 0.101854)
		(layer "F.Cu")
		(net "M_A_CPU0_SB_DQ<23>")
	)
	(segment
		(start 318.19215 -205.3336)
		(end 317.813182 -205.712568)
		(width 0.20066)
		(layer "F.Cu")
		(net "M_A_CPU0_SB_DQ<23>")
	)
	(segment
		(start 316.76975 -205.3336)
		(end 316.390782 -205.712568)
		(width 0.20066)
		(layer "F.Cu")
		(net "M_A_CPU0_SB_DQ<23>")
	)
	(segment
		(start 327.641204 -212.900514)
		(end 320.07429 -205.3336)
		(width 0.20066)
		(layer "F.Cu")
		(net "M_A_CPU0_SB_DQ<23>")
	)
	(segment
		(start 329.630532 -224.096834)
		(end 328.025252 -222.491554)
		(width 0.1016)
		(layer "F.Cu")
		(net "M_A_CPU0_SB_DQ<23>")
	)
	(segment
		(start 328.025252 -213.284562)
		(end 327.641204 -212.900514)
		(width 0.1016)
		(layer "F.Cu")
		(net "M_A_CPU0_SB_DQ<23>")
	)
	(segment
		(start 332.14691 -228.17455)
		(end 331.569314 -228.17455)
		(width 0.1016)
		(layer "F.Cu")
		(net "M_A_CPU0_SB_DQ<23>")
	)
	(segment
		(start 319.235582 -205.712568)
		(end 318.90335 -205.712568)
		(width 0.20066)
		(layer "F.Cu")
		(net "M_A_CPU0_SB_DQ<23>")
	)
	(segment
		(start 318.90335 -205.712568)
		(end 318.524382 -205.3336)
		(width 0.20066)
		(layer "F.Cu")
		(net "M_A_CPU0_SB_DQ<23>")
	)
	(segment
		(start 328.025252 -222.491554)
		(end 328.025252 -213.284562)
		(width 0.1016)
		(layer "F.Cu")
		(net "M_A_CPU0_SB_DQ<23>")
	)
	(segment
		(start 314.979304 -204.72654)
		(end 313.74715 -204.72654)
		(width 0.20066)
		(layer "F.Cu")
		(net "M_A_CPU0_SB_DQ<23>")
	)
	(segment
		(start 310.088026 -205.391512)
		(end 310.452516 -205.391512)
		(width 0.20066)
		(layer "F.Cu")
		(net "M_A_CPU0_SB_DQ<23>")
	)
	(segment
		(start 307.77815 -205.391512)
		(end 307.82768 -205.391512)
		(width 0.101854)
		(layer "F.Cu")
		(net "M_A_CPU0_SB_DQ<23>")
	)
	(segment
		(start 333.054452 -228.483414)
		(end 332.73238 -228.17455)
		(width 0.088646)
		(layer "F.Cu")
		(net "M_A_CPU0_SB_DQ<23>")
	)
	(segment
		(start 310.586882 -204.93355)
		(end 310.771286 -204.749146)
		(width 0.20066)
		(layer "F.Cu")
		(net "M_A_CPU0_SB_DQ<23>")
	)
	(segment
		(start 310.586882 -205.257146)
		(end 310.586882 -204.93355)
		(width 0.20066)
		(layer "F.Cu")
		(net "M_A_CPU0_SB_DQ<23>")
	)
	(segment
		(start 317.101982 -205.3336)
		(end 316.76975 -205.3336)
		(width 0.20066)
		(layer "F.Cu")
		(net "M_A_CPU0_SB_DQ<23>")
	)
	(segment
		(start 319.61455 -205.3336)
		(end 319.235582 -205.712568)
		(width 0.20066)
		(layer "F.Cu")
		(net "M_A_CPU0_SB_DQ<23>")
	)
	(segment
		(start 310.452516 -205.391512)
		(end 310.586882 -205.257146)
		(width 0.20066)
		(layer "F.Cu")
		(net "M_A_CPU0_SB_DQ<23>")
	)
	(segment
		(start 313.50712 -204.96657)
		(end 312.987182 -204.96657)
		(width 0.20066)
		(layer "F.Cu")
		(net "M_A_CPU0_SB_DQ<23>")
	)
	(segment
		(start 305.443382 -204.96657)
		(end 307.118766 -204.96657)
		(width 0.20066)
		(layer "F.Cu")
		(net "M_A_CPU0_SB_DQ<23>")
	)
	(segment
		(start 307.759354 -205.410308)
		(end 307.76291 -205.406752)
		(width 0.20066)
		(layer "F.Cu")
		(net "M_A_CPU0_SB_DQ<23>")
	)
	(segment
		(start 318.524382 -205.3336)
		(end 318.19215 -205.3336)
		(width 0.20066)
		(layer "F.Cu")
		(net "M_A_CPU0_SB_DQ<23>")
	)
	(segment
		(start 307.76291 -205.406752)
		(end 307.77815 -205.391512)
		(width 0.101854)
		(layer "F.Cu")
		(net "M_A_CPU0_SB_DQ<23>")
	)
	(segment
		(start 310.771286 -204.749146)
		(end 311.056274 -204.749146)
		(width 0.20066)
		(layer "F.Cu")
		(net "M_A_CPU0_SB_DQ<23>")
	)
	(segment
		(start 307.562504 -205.410308)
		(end 307.759354 -205.410308)
		(width 0.20066)
		(layer "F.Cu")
		(net "M_A_CPU0_SB_DQ<23>")
	)
	(segment
		(start 333.212694 -228.566726)
		(end 333.054452 -228.483414)
		(width 0.088646)
		(layer "F.Cu")
		(net "M_A_CPU0_SB_DQ<23>")
	)
	(segment
		(start 315.965332 -205.712568)
		(end 314.979304 -204.72654)
		(width 0.20066)
		(layer "F.Cu")
		(net "M_A_CPU0_SB_DQ<23>")
	)
	(segment
		(start 311.056274 -204.749146)
		(end 311.273698 -204.96657)
		(width 0.20066)
		(layer "F.Cu")
		(net "M_A_CPU0_SB_DQ<23>")
	)
	(segment
		(start 320.07429 -205.3336)
		(end 319.61455 -205.3336)
		(width 0.20066)
		(layer "F.Cu")
		(net "M_A_CPU0_SB_DQ<23>")
	)
	(segment
		(start 331.569314 -228.17455)
		(end 329.630532 -226.235768)
		(width 0.1016)
		(layer "F.Cu")
		(net "M_A_CPU0_SB_DQ<23>")
	)
	(segment
		(start 307.82768 -205.391512)
		(end 310.03748 -205.391512)
		(width 0.1016)
		(layer "F.Cu")
		(net "M_A_CPU0_SB_DQ<23>")
	)
	(segment
		(start 333.755238 -228.522022)
		(end 333.555594 -228.594666)
		(width 0.088646)
		(layer "F.Cu")
		(net "M_A_CPU0_SB_DQ<23>")
	)
	(segment
		(start 317.813182 -205.712568)
		(end 317.48095 -205.712568)
		(width 0.20066)
		(layer "F.Cu")
		(net "M_A_CPU0_SB_DQ<23>")
	)
	(segment
		(start 333.296768 -228.59619)
		(end 333.212694 -228.566726)
		(width 0.088646)
		(layer "F.Cu")
		(net "M_A_CPU0_SB_DQ<23>")
	)
	(segment
		(start 313.74715 -204.72654)
		(end 313.50712 -204.96657)
		(width 0.20066)
		(layer "F.Cu")
		(net "M_A_CPU0_SB_DQ<23>")
	)
	(segment
		(start 317.48095 -205.712568)
		(end 317.101982 -205.3336)
		(width 0.20066)
		(layer "F.Cu")
		(net "M_A_CPU0_SB_DQ<23>")
	)
	(segment
		(start 334.137254 -228.719126)
		(end 333.984854 -228.571298)
		(width 0.088646)
		(layer "F.Cu")
		(net "M_A_CPU0_SB_DQ<23>")
	)
	(segment
		(start 332.73238 -228.17455)
		(end 332.14691 -228.17455)
		(width 0.088646)
		(layer "F.Cu")
		(net "M_A_CPU0_SB_DQ<23>")
	)
	(segment
		(start 316.390782 -205.712568)
		(end 315.965332 -205.712568)
		(width 0.20066)
		(layer "F.Cu")
		(net "M_A_CPU0_SB_DQ<23>")
	)
	(segment
		(start 307.118766 -204.96657)
		(end 307.562504 -205.410308)
		(width 0.20066)
		(layer "F.Cu")
		(net "M_A_CPU0_SB_DQ<23>")
	)
	(segment
		(start 311.273698 -204.96657)
		(end 312.987182 -204.96657)
		(width 0.20066)
		(layer "F.Cu")
		(net "M_A_CPU0_SB_DQ<23>")
	)
	(arc
		(start 333.555594 -228.594666)
		(mid 333.426312 -228.617847)
		(end 333.296768 -228.59619)
		(width 0.088646)
		(layer "F.Cu")
		(net "M_A_CPU0_SB_DQ<23>")
	)
	(arc
		(start 334.675734 -228.99497)
		(mid 334.384813 -228.899375)
		(end 334.137254 -228.719126)
		(width 0.088646)
		(layer "F.Cu")
		(net "M_A_CPU0_SB_DQ<23>")
	)
	(arc
		(start 333.984854 -228.571298)
		(mid 333.877127 -228.513613)
		(end 333.755238 -228.522022)
		(width 0.088646)
		(layer "F.Cu")
		(net "M_A_CPU0_SB_DQ<23>")
	)
	(segment
		(start 317.313564 -207.387444)
		(end 316.917832 -206.991712)
		(width 0.20066)
		(layer "F.Cu")
		(net "M_A_CPU0_SB_DQ<22>")
	)
	(segment
		(start 310.080406 -207.091534)
		(end 310.088026 -207.099154)
		(width 0.101854)
		(layer "F.Cu")
		(net "M_A_CPU0_SB_DQ<22>")
	)
	(segment
		(start 311.984898 -206.666592)
		(end 312.987182 -206.666592)
		(width 0.20066)
		(layer "F.Cu")
		(net "M_A_CPU0_SB_DQ<22>")
	)
	(segment
		(start 327.415652 -214.48395)
		(end 326.73671 -213.805008)
		(width 0.1016)
		(layer "F.Cu")
		(net "M_A_CPU0_SB_DQ<22>")
	)
	(segment
		(start 335.14538 -229.808786)
		(end 334.440784 -229.401878)
		(width 0.088646)
		(layer "F.Cu")
		(net "M_A_CPU0_SB_DQ<22>")
	)
	(segment
		(start 327.415652 -222.744538)
		(end 327.415652 -214.48395)
		(width 0.1016)
		(layer "F.Cu")
		(net "M_A_CPU0_SB_DQ<22>")
	)
	(segment
		(start 315.741812 -207.387444)
		(end 314.723018 -206.36865)
		(width 0.20066)
		(layer "F.Cu")
		(net "M_A_CPU0_SB_DQ<22>")
	)
	(segment
		(start 307.38699 -207.108552)
		(end 307.76291 -207.108552)
		(width 0.20066)
		(layer "F.Cu")
		(net "M_A_CPU0_SB_DQ<22>")
	)
	(segment
		(start 309.804054 -207.091534)
		(end 310.080406 -207.091534)
		(width 0.101854)
		(layer "F.Cu")
		(net "M_A_CPU0_SB_DQ<22>")
	)
	(segment
		(start 331.803248 -229.366826)
		(end 331.803248 -229.271068)
		(width 0.088646)
		(layer "F.Cu")
		(net "M_A_CPU0_SB_DQ<22>")
	)
	(segment
		(start 318.024764 -206.991712)
		(end 317.629032 -207.387444)
		(width 0.20066)
		(layer "F.Cu")
		(net "M_A_CPU0_SB_DQ<22>")
	)
	(segment
		(start 314.290202 -206.36865)
		(end 313.99226 -206.666592)
		(width 0.20066)
		(layer "F.Cu")
		(net "M_A_CPU0_SB_DQ<22>")
	)
	(segment
		(start 307.785262 -207.108552)
		(end 307.80228 -207.091534)
		(width 0.101854)
		(layer "F.Cu")
		(net "M_A_CPU0_SB_DQ<22>")
	)
	(segment
		(start 332.80223 -229.587298)
		(end 332.740508 -229.64902)
		(width 0.088646)
		(layer "F.Cu")
		(net "M_A_CPU0_SB_DQ<22>")
	)
	(segment
		(start 332.236826 -229.64902)
		(end 331.978508 -229.542086)
		(width 0.088646)
		(layer "F.Cu")
		(net "M_A_CPU0_SB_DQ<22>")
	)
	(segment
		(start 326.73671 -213.805008)
		(end 319.923414 -206.991712)
		(width 0.20066)
		(layer "F.Cu")
		(net "M_A_CPU0_SB_DQ<22>")
	)
	(segment
		(start 319.051432 -207.387444)
		(end 318.735964 -207.387444)
		(width 0.20066)
		(layer "F.Cu")
		(net "M_A_CPU0_SB_DQ<22>")
	)
	(segment
		(start 329.020932 -224.349818)
		(end 327.415652 -222.744538)
		(width 0.1016)
		(layer "F.Cu")
		(net "M_A_CPU0_SB_DQ<22>")
	)
	(segment
		(start 305.443382 -206.666592)
		(end 306.94503 -206.666592)
		(width 0.20066)
		(layer "F.Cu")
		(net "M_A_CPU0_SB_DQ<22>")
	)
	(segment
		(start 310.698388 -206.610712)
		(end 310.887618 -206.421482)
		(width 0.20066)
		(layer "F.Cu")
		(net "M_A_CPU0_SB_DQ<22>")
	)
	(segment
		(start 307.80228 -207.091534)
		(end 309.804054 -207.091534)
		(width 0.1016)
		(layer "F.Cu")
		(net "M_A_CPU0_SB_DQ<22>")
	)
	(segment
		(start 316.602364 -206.991712)
		(end 316.206632 -207.387444)
		(width 0.20066)
		(layer "F.Cu")
		(net "M_A_CPU0_SB_DQ<22>")
	)
	(segment
		(start 332.740508 -229.64902)
		(end 332.236826 -229.64902)
		(width 0.088646)
		(layer "F.Cu")
		(net "M_A_CPU0_SB_DQ<22>")
	)
	(segment
		(start 310.698388 -206.89951)
		(end 310.698388 -206.610712)
		(width 0.20066)
		(layer "F.Cu")
		(net "M_A_CPU0_SB_DQ<22>")
	)
	(segment
		(start 331.633576 -229.101396)
		(end 329.020932 -226.488752)
		(width 0.1016)
		(layer "F.Cu")
		(net "M_A_CPU0_SB_DQ<22>")
	)
	(segment
		(start 307.76291 -207.108552)
		(end 307.785262 -207.108552)
		(width 0.101854)
		(layer "F.Cu")
		(net "M_A_CPU0_SB_DQ<22>")
	)
	(segment
		(start 306.94503 -206.666592)
		(end 307.38699 -207.108552)
		(width 0.20066)
		(layer "F.Cu")
		(net "M_A_CPU0_SB_DQ<22>")
	)
	(segment
		(start 332.872334 -229.587298)
		(end 332.80223 -229.587298)
		(width 0.088646)
		(layer "F.Cu")
		(net "M_A_CPU0_SB_DQ<22>")
	)
	(segment
		(start 319.447164 -206.991712)
		(end 319.051432 -207.387444)
		(width 0.20066)
		(layer "F.Cu")
		(net "M_A_CPU0_SB_DQ<22>")
	)
	(segment
		(start 311.739788 -206.421482)
		(end 311.984898 -206.666592)
		(width 0.20066)
		(layer "F.Cu")
		(net "M_A_CPU0_SB_DQ<22>")
	)
	(segment
		(start 310.498744 -207.099154)
		(end 310.698388 -206.89951)
		(width 0.20066)
		(layer "F.Cu")
		(net "M_A_CPU0_SB_DQ<22>")
	)
	(segment
		(start 318.735964 -207.387444)
		(end 318.340232 -206.991712)
		(width 0.20066)
		(layer "F.Cu")
		(net "M_A_CPU0_SB_DQ<22>")
	)
	(segment
		(start 333.165196 -229.356666)
		(end 332.977998 -229.543864)
		(width 0.088646)
		(layer "F.Cu")
		(net "M_A_CPU0_SB_DQ<22>")
	)
	(segment
		(start 333.18704 -229.345236)
		(end 333.165196 -229.356666)
		(width 0.088646)
		(layer "F.Cu")
		(net "M_A_CPU0_SB_DQ<22>")
	)
	(segment
		(start 310.887618 -206.421482)
		(end 311.739788 -206.421482)
		(width 0.20066)
		(layer "F.Cu")
		(net "M_A_CPU0_SB_DQ<22>")
	)
	(segment
		(start 314.723018 -206.36865)
		(end 314.290202 -206.36865)
		(width 0.20066)
		(layer "F.Cu")
		(net "M_A_CPU0_SB_DQ<22>")
	)
	(segment
		(start 329.020932 -226.488752)
		(end 329.020932 -224.349818)
		(width 0.1016)
		(layer "F.Cu")
		(net "M_A_CPU0_SB_DQ<22>")
	)
	(segment
		(start 331.978508 -229.542086)
		(end 331.803248 -229.366826)
		(width 0.088646)
		(layer "F.Cu")
		(net "M_A_CPU0_SB_DQ<22>")
	)
	(segment
		(start 331.803248 -229.271068)
		(end 331.633576 -229.101396)
		(width 0.088646)
		(layer "F.Cu")
		(net "M_A_CPU0_SB_DQ<22>")
	)
	(segment
		(start 317.629032 -207.387444)
		(end 317.313564 -207.387444)
		(width 0.20066)
		(layer "F.Cu")
		(net "M_A_CPU0_SB_DQ<22>")
	)
	(segment
		(start 316.206632 -207.387444)
		(end 315.741812 -207.387444)
		(width 0.20066)
		(layer "F.Cu")
		(net "M_A_CPU0_SB_DQ<22>")
	)
	(segment
		(start 310.088026 -207.099154)
		(end 310.498744 -207.099154)
		(width 0.20066)
		(layer "F.Cu")
		(net "M_A_CPU0_SB_DQ<22>")
	)
	(segment
		(start 318.340232 -206.991712)
		(end 318.024764 -206.991712)
		(width 0.20066)
		(layer "F.Cu")
		(net "M_A_CPU0_SB_DQ<22>")
	)
	(segment
		(start 316.917832 -206.991712)
		(end 316.602364 -206.991712)
		(width 0.20066)
		(layer "F.Cu")
		(net "M_A_CPU0_SB_DQ<22>")
	)
	(segment
		(start 319.923414 -206.991712)
		(end 319.447164 -206.991712)
		(width 0.20066)
		(layer "F.Cu")
		(net "M_A_CPU0_SB_DQ<22>")
	)
	(segment
		(start 313.99226 -206.666592)
		(end 312.987182 -206.666592)
		(width 0.20066)
		(layer "F.Cu")
		(net "M_A_CPU0_SB_DQ<22>")
	)
	(arc
		(start 334.440784 -229.401878)
		(mid 334.205834 -229.338918)
		(end 333.970884 -229.401878)
		(width 0.088646)
		(layer "F.Cu")
		(net "M_A_CPU0_SB_DQ<22>")
	)
	(arc
		(start 333.970884 -229.401878)
		(mid 333.735934 -229.464838)
		(end 333.500984 -229.401878)
		(width 0.088646)
		(layer "F.Cu")
		(net "M_A_CPU0_SB_DQ<22>")
	)
	(arc
		(start 332.977998 -229.543864)
		(mid 332.929462 -229.576043)
		(end 332.872334 -229.587298)
		(width 0.088646)
		(layer "F.Cu")
		(net "M_A_CPU0_SB_DQ<22>")
	)
	(arc
		(start 333.500984 -229.401878)
		(mid 333.348963 -229.346128)
		(end 333.18704 -229.345236)
		(width 0.088646)
		(layer "F.Cu")
		(net "M_A_CPU0_SB_DQ<22>")
	)
	(segment
		(start 332.894432 -228.634036)
		(end 332.61554 -228.48951)
		(width 0.088646)
		(layer "F.Cu")
		(net "M_A_CPU0_SB_DQ<21>")
	)
	(segment
		(start 309.936642 -205.877922)
		(end 309.875428 -205.816708)
		(width 0.20066)
		(layer "F.Cu")
		(net "M_A_CPU0_SB_DQ<21>")
	)
	(segment
		(start 306.644294 -205.391766)
		(end 306.848002 -205.391766)
		(width 0.20066)
		(layer "F.Cu")
		(net "M_A_CPU0_SB_DQ<21>")
	)
	(segment
		(start 306.289202 -205.391766)
		(end 306.644294 -205.391766)
		(width 0.101854)
		(layer "F.Cu")
		(net "M_A_CPU0_SB_DQ<21>")
	)
	(segment
		(start 329.325732 -224.223326)
		(end 327.720452 -222.618046)
		(width 0.1016)
		(layer "F.Cu")
		(net "M_A_CPU0_SB_DQ<21>")
	)
	(segment
		(start 320.188336 -206.35214)
		(end 315.636148 -206.35214)
		(width 0.20066)
		(layer "F.Cu")
		(net "M_A_CPU0_SB_DQ<21>")
	)
	(segment
		(start 306.848002 -205.391766)
		(end 307.272944 -205.816708)
		(width 0.20066)
		(layer "F.Cu")
		(net "M_A_CPU0_SB_DQ<21>")
	)
	(segment
		(start 303.587404 -205.583282)
		(end 303.790604 -205.380082)
		(width 0.20066)
		(layer "F.Cu")
		(net "M_A_CPU0_SB_DQ<21>")
	)
	(segment
		(start 332.14691 -228.48951)
		(end 331.452982 -228.48951)
		(width 0.1016)
		(layer "F.Cu")
		(net "M_A_CPU0_SB_DQ<21>")
	)
	(segment
		(start 327.720452 -222.618046)
		(end 327.720452 -213.884256)
		(width 0.1016)
		(layer "F.Cu")
		(net "M_A_CPU0_SB_DQ<21>")
	)
	(segment
		(start 303.587404 -205.863698)
		(end 303.587404 -205.583282)
		(width 0.20066)
		(layer "F.Cu")
		(net "M_A_CPU0_SB_DQ<21>")
	)
	(segment
		(start 333.196946 -228.783642)
		(end 332.894432 -228.634036)
		(width 0.088646)
		(layer "F.Cu")
		(net "M_A_CPU0_SB_DQ<21>")
	)
	(segment
		(start 312.082434 -205.376526)
		(end 311.84088 -205.376526)
		(width 0.101854)
		(layer "F.Cu")
		(net "M_A_CPU0_SB_DQ<21>")
	)
	(segment
		(start 327.720452 -213.884256)
		(end 327.18883 -213.352634)
		(width 0.1016)
		(layer "F.Cu")
		(net "M_A_CPU0_SB_DQ<21>")
	)
	(segment
		(start 315.636148 -206.35214)
		(end 314.65012 -205.366112)
		(width 0.20066)
		(layer "F.Cu")
		(net "M_A_CPU0_SB_DQ<21>")
	)
	(segment
		(start 303.373282 -206.07782)
		(end 303.587404 -205.863698)
		(width 0.20066)
		(layer "F.Cu")
		(net "M_A_CPU0_SB_DQ<21>")
	)
	(segment
		(start 302.648366 -206.07782)
		(end 303.373282 -206.07782)
		(width 0.20066)
		(layer "F.Cu")
		(net "M_A_CPU0_SB_DQ<21>")
	)
	(segment
		(start 333.735934 -228.99497)
		(end 333.196946 -228.783642)
		(width 0.088646)
		(layer "F.Cu")
		(net "M_A_CPU0_SB_DQ<21>")
	)
	(segment
		(start 329.325732 -226.36226)
		(end 329.325732 -224.223326)
		(width 0.1016)
		(layer "F.Cu")
		(net "M_A_CPU0_SB_DQ<21>")
	)
	(segment
		(start 327.18883 -213.352634)
		(end 320.188336 -206.35214)
		(width 0.20066)
		(layer "F.Cu")
		(net "M_A_CPU0_SB_DQ<21>")
	)
	(segment
		(start 313.966352 -205.366112)
		(end 313.940952 -205.391512)
		(width 0.101854)
		(layer "F.Cu")
		(net "M_A_CPU0_SB_DQ<21>")
	)
	(segment
		(start 314.15228 -205.366112)
		(end 313.966352 -205.366112)
		(width 0.101854)
		(layer "F.Cu")
		(net "M_A_CPU0_SB_DQ<21>")
	)
	(segment
		(start 302.387254 -205.816708)
		(end 302.648366 -206.07782)
		(width 0.20066)
		(layer "F.Cu")
		(net "M_A_CPU0_SB_DQ<21>")
	)
	(segment
		(start 301.343314 -205.816708)
		(end 302.387254 -205.816708)
		(width 0.20066)
		(layer "F.Cu")
		(net "M_A_CPU0_SB_DQ<21>")
	)
	(segment
		(start 311.11825 -205.736444)
		(end 310.976772 -205.877922)
		(width 0.20066)
		(layer "F.Cu")
		(net "M_A_CPU0_SB_DQ<21>")
	)
	(segment
		(start 310.976772 -205.877922)
		(end 309.936642 -205.877922)
		(width 0.20066)
		(layer "F.Cu")
		(net "M_A_CPU0_SB_DQ<21>")
	)
	(segment
		(start 304.319178 -205.380082)
		(end 304.357278 -205.391766)
		(width 0.1016)
		(layer "F.Cu")
		(net "M_A_CPU0_SB_DQ<21>")
	)
	(segment
		(start 304.357278 -205.391766)
		(end 306.289202 -205.391766)
		(width 0.1016)
		(layer "F.Cu")
		(net "M_A_CPU0_SB_DQ<21>")
	)
	(segment
		(start 314.65012 -205.366112)
		(end 314.15228 -205.366112)
		(width 0.20066)
		(layer "F.Cu")
		(net "M_A_CPU0_SB_DQ<21>")
	)
	(segment
		(start 309.875428 -205.816708)
		(end 308.887114 -205.816708)
		(width 0.20066)
		(layer "F.Cu")
		(net "M_A_CPU0_SB_DQ<21>")
	)
	(segment
		(start 312.12536 -205.391512)
		(end 312.082434 -205.376526)
		(width 0.1016)
		(layer "F.Cu")
		(net "M_A_CPU0_SB_DQ<21>")
	)
	(segment
		(start 332.61554 -228.48951)
		(end 332.14691 -228.48951)
		(width 0.088646)
		(layer "F.Cu")
		(net "M_A_CPU0_SB_DQ<21>")
	)
	(segment
		(start 311.11825 -205.45933)
		(end 311.11825 -205.736444)
		(width 0.20066)
		(layer "F.Cu")
		(net "M_A_CPU0_SB_DQ<21>")
	)
	(segment
		(start 307.272944 -205.816708)
		(end 308.887114 -205.816708)
		(width 0.20066)
		(layer "F.Cu")
		(net "M_A_CPU0_SB_DQ<21>")
	)
	(segment
		(start 303.790604 -205.380082)
		(end 304.319178 -205.380082)
		(width 0.20066)
		(layer "F.Cu")
		(net "M_A_CPU0_SB_DQ<21>")
	)
	(segment
		(start 331.452982 -228.48951)
		(end 329.325732 -226.36226)
		(width 0.1016)
		(layer "F.Cu")
		(net "M_A_CPU0_SB_DQ<21>")
	)
	(segment
		(start 311.201054 -205.376526)
		(end 311.11825 -205.45933)
		(width 0.20066)
		(layer "F.Cu")
		(net "M_A_CPU0_SB_DQ<21>")
	)
	(segment
		(start 313.940952 -205.391512)
		(end 312.12536 -205.391512)
		(width 0.1016)
		(layer "F.Cu")
		(net "M_A_CPU0_SB_DQ<21>")
	)
	(segment
		(start 311.84088 -205.376526)
		(end 311.201054 -205.376526)
		(width 0.20066)
		(layer "F.Cu")
		(net "M_A_CPU0_SB_DQ<21>")
	)
	(segment
		(start 312.00471 -207.049878)
		(end 311.84088 -207.049878)
		(width 0.1016)
		(layer "F.Cu")
		(net "M_A_CPU0_SB_DQ<20>")
	)
	(segment
		(start 306.289202 -207.091534)
		(end 306.644294 -207.091534)
		(width 0.101854)
		(layer "F.Cu")
		(net "M_A_CPU0_SB_DQ<20>")
	)
	(segment
		(start 303.68621 -207.083406)
		(end 304.319178 -207.083406)
		(width 0.20066)
		(layer "F.Cu")
		(net "M_A_CPU0_SB_DQ<20>")
	)
	(segment
		(start 313.933586 -207.054196)
		(end 313.843416 -207.091534)
		(width 0.1016)
		(layer "F.Cu")
		(net "M_A_CPU0_SB_DQ<20>")
	)
	(segment
		(start 333.224886 -229.84968)
		(end 332.200504 -229.84968)
		(width 0.088646)
		(layer "F.Cu")
		(net "M_A_CPU0_SB_DQ<20>")
	)
	(segment
		(start 312.12536 -207.091534)
		(end 312.00471 -207.049878)
		(width 0.1016)
		(layer "F.Cu")
		(net "M_A_CPU0_SB_DQ<20>")
	)
	(segment
		(start 328.716132 -224.47631)
		(end 327.110852 -222.87103)
		(width 0.1016)
		(layer "F.Cu")
		(net "M_A_CPU0_SB_DQ<20>")
	)
	(segment
		(start 311.426098 -207.049878)
		(end 310.959246 -207.51673)
		(width 0.20066)
		(layer "F.Cu")
		(net "M_A_CPU0_SB_DQ<20>")
	)
	(segment
		(start 314.17768 -207.054196)
		(end 313.933586 -207.054196)
		(width 0.1016)
		(layer "F.Cu")
		(net "M_A_CPU0_SB_DQ<20>")
	)
	(segment
		(start 304.327306 -207.091534)
		(end 306.289202 -207.091534)
		(width 0.1016)
		(layer "F.Cu")
		(net "M_A_CPU0_SB_DQ<20>")
	)
	(segment
		(start 306.644294 -207.091534)
		(end 306.7685 -207.091534)
		(width 0.20066)
		(layer "F.Cu")
		(net "M_A_CPU0_SB_DQ<20>")
	)
	(segment
		(start 326.498458 -214.471504)
		(end 320.05397 -208.027016)
		(width 0.20066)
		(layer "F.Cu")
		(net "M_A_CPU0_SB_DQ<20>")
	)
	(segment
		(start 327.110852 -222.87103)
		(end 327.110852 -215.083898)
		(width 0.1016)
		(layer "F.Cu")
		(net "M_A_CPU0_SB_DQ<20>")
	)
	(segment
		(start 328.716132 -226.615498)
		(end 328.716132 -224.47631)
		(width 0.1016)
		(layer "F.Cu")
		(net "M_A_CPU0_SB_DQ<20>")
	)
	(segment
		(start 320.05397 -208.027016)
		(end 315.441584 -208.027016)
		(width 0.20066)
		(layer "F.Cu")
		(net "M_A_CPU0_SB_DQ<20>")
	)
	(segment
		(start 304.319178 -207.083406)
		(end 304.327306 -207.091534)
		(width 0.1016)
		(layer "F.Cu")
		(net "M_A_CPU0_SB_DQ<20>")
	)
	(segment
		(start 315.441584 -208.027016)
		(end 314.468764 -207.054196)
		(width 0.20066)
		(layer "F.Cu")
		(net "M_A_CPU0_SB_DQ<20>")
	)
	(segment
		(start 313.843416 -207.091534)
		(end 312.12536 -207.091534)
		(width 0.1016)
		(layer "F.Cu")
		(net "M_A_CPU0_SB_DQ<20>")
	)
	(segment
		(start 314.468764 -207.054196)
		(end 314.17768 -207.054196)
		(width 0.20066)
		(layer "F.Cu")
		(net "M_A_CPU0_SB_DQ<20>")
	)
	(segment
		(start 302.653446 -207.51673)
		(end 302.90643 -207.769714)
		(width 0.20066)
		(layer "F.Cu")
		(net "M_A_CPU0_SB_DQ<20>")
	)
	(segment
		(start 303.523396 -207.24622)
		(end 303.68621 -207.083406)
		(width 0.20066)
		(layer "F.Cu")
		(net "M_A_CPU0_SB_DQ<20>")
	)
	(segment
		(start 333.26578 -229.808786)
		(end 333.224886 -229.84968)
		(width 0.088646)
		(layer "F.Cu")
		(net "M_A_CPU0_SB_DQ<20>")
	)
	(segment
		(start 331.773276 -229.672642)
		(end 331.417676 -229.317042)
		(width 0.088646)
		(layer "F.Cu")
		(net "M_A_CPU0_SB_DQ<20>")
	)
	(segment
		(start 311.84088 -207.049878)
		(end 311.426098 -207.049878)
		(width 0.20066)
		(layer "F.Cu")
		(net "M_A_CPU0_SB_DQ<20>")
	)
	(segment
		(start 327.110852 -215.083898)
		(end 326.498458 -214.471504)
		(width 0.1016)
		(layer "F.Cu")
		(net "M_A_CPU0_SB_DQ<20>")
	)
	(segment
		(start 332.200504 -229.84968)
		(end 331.773276 -229.672642)
		(width 0.088646)
		(layer "F.Cu")
		(net "M_A_CPU0_SB_DQ<20>")
	)
	(segment
		(start 301.343314 -207.51673)
		(end 302.653446 -207.51673)
		(width 0.20066)
		(layer "F.Cu")
		(net "M_A_CPU0_SB_DQ<20>")
	)
	(segment
		(start 310.959246 -207.51673)
		(end 308.887114 -207.51673)
		(width 0.20066)
		(layer "F.Cu")
		(net "M_A_CPU0_SB_DQ<20>")
	)
	(segment
		(start 303.287938 -207.769714)
		(end 303.523396 -207.534256)
		(width 0.20066)
		(layer "F.Cu")
		(net "M_A_CPU0_SB_DQ<20>")
	)
	(segment
		(start 302.90643 -207.769714)
		(end 303.287938 -207.769714)
		(width 0.20066)
		(layer "F.Cu")
		(net "M_A_CPU0_SB_DQ<20>")
	)
	(segment
		(start 306.7685 -207.091534)
		(end 307.193696 -207.51673)
		(width 0.20066)
		(layer "F.Cu")
		(net "M_A_CPU0_SB_DQ<20>")
	)
	(segment
		(start 307.193696 -207.51673)
		(end 308.887114 -207.51673)
		(width 0.20066)
		(layer "F.Cu")
		(net "M_A_CPU0_SB_DQ<20>")
	)
	(segment
		(start 331.417676 -229.317042)
		(end 328.716132 -226.615498)
		(width 0.1016)
		(layer "F.Cu")
		(net "M_A_CPU0_SB_DQ<20>")
	)
	(segment
		(start 303.523396 -207.534256)
		(end 303.523396 -207.24622)
		(width 0.20066)
		(layer "F.Cu")
		(net "M_A_CPU0_SB_DQ<20>")
	)
	(segment
		(start 303.71923 -230.000302)
		(end 303.523396 -230.196136)
		(width 0.20066)
		(layer "F.Cu")
		(net "M_A_CPU0_SB_DQ<1>")
	)
	(segment
		(start 304.319178 -230.000302)
		(end 303.71923 -230.000302)
		(width 0.20066)
		(layer "F.Cu")
		(net "M_A_CPU0_SB_DQ<1>")
	)
	(segment
		(start 304.415444 -230.000302)
		(end 304.34788 -230.000302)
		(width 0.1016)
		(layer "F.Cu")
		(net "M_A_CPU0_SB_DQ<1>")
	)
	(segment
		(start 303.289208 -230.71836)
		(end 302.90516 -230.71836)
		(width 0.20066)
		(layer "F.Cu")
		(net "M_A_CPU0_SB_DQ<1>")
	)
	(segment
		(start 306.34051 -230.026972)
		(end 306.289202 -230.041704)
		(width 0.1016)
		(layer "F.Cu")
		(net "M_A_CPU0_SB_DQ<1>")
	)
	(segment
		(start 304.550826 -230.041704)
		(end 304.415444 -230.000302)
		(width 0.1016)
		(layer "F.Cu")
		(net "M_A_CPU0_SB_DQ<1>")
	)
	(segment
		(start 304.34788 -230.000302)
		(end 304.319178 -230.000302)
		(width 0.101854)
		(layer "F.Cu")
		(net "M_A_CPU0_SB_DQ<1>")
	)
	(segment
		(start 303.523396 -230.196136)
		(end 303.523396 -230.484172)
		(width 0.20066)
		(layer "F.Cu")
		(net "M_A_CPU0_SB_DQ<1>")
	)
	(segment
		(start 308.887114 -230.466646)
		(end 307.272944 -230.466646)
		(width 0.20066)
		(layer "F.Cu")
		(net "M_A_CPU0_SB_DQ<1>")
	)
	(segment
		(start 336.555334 -238.761524)
		(end 336.55508 -238.76127)
		(width 0.20066)
		(layer "F.Cu")
		(net "M_A_CPU0_SB_DQ<1>")
	)
	(segment
		(start 306.83327 -230.026972)
		(end 306.644294 -230.026972)
		(width 0.20066)
		(layer "F.Cu")
		(net "M_A_CPU0_SB_DQ<1>")
	)
	(segment
		(start 336.55508 -238.76127)
		(end 336.55508 -238.225584)
		(width 0.20066)
		(layer "F.Cu")
		(net "M_A_CPU0_SB_DQ<1>")
	)
	(segment
		(start 306.644294 -230.026972)
		(end 306.34051 -230.026972)
		(width 0.101854)
		(layer "F.Cu")
		(net "M_A_CPU0_SB_DQ<1>")
	)
	(segment
		(start 302.653446 -230.466646)
		(end 301.343314 -230.466646)
		(width 0.20066)
		(layer "F.Cu")
		(net "M_A_CPU0_SB_DQ<1>")
	)
	(segment
		(start 303.523396 -230.484172)
		(end 303.289208 -230.71836)
		(width 0.20066)
		(layer "F.Cu")
		(net "M_A_CPU0_SB_DQ<1>")
	)
	(segment
		(start 306.289202 -230.041704)
		(end 304.550826 -230.041704)
		(width 0.1016)
		(layer "F.Cu")
		(net "M_A_CPU0_SB_DQ<1>")
	)
	(segment
		(start 307.272944 -230.466646)
		(end 306.83327 -230.026972)
		(width 0.20066)
		(layer "F.Cu")
		(net "M_A_CPU0_SB_DQ<1>")
	)
	(segment
		(start 309.992014 -230.466646)
		(end 308.887114 -230.466646)
		(width 0.20066)
		(layer "F.Cu")
		(net "M_A_CPU0_SB_DQ<1>")
	)
	(segment
		(start 302.90516 -230.71836)
		(end 302.653446 -230.466646)
		(width 0.20066)
		(layer "F.Cu")
		(net "M_A_CPU0_SB_DQ<1>")
	)
	(segment
		(start 310.473852 -229.505002)
		(end 310.473852 -230.273352)
		(width 0.18288)
		(layer "In2.Cu")
		(net "M_A_CPU0_SB_DQ<1>")
	)
	(segment
		(start 331.856334 -238.790734)
		(end 331.461872 -238.790734)
		(width 0.088646)
		(layer "In2.Cu")
		(net "M_A_CPU0_SB_DQ<1>")
	)
	(segment
		(start 313.195462 -230.603298)
		(end 312.695336 -230.603298)
		(width 0.18288)
		(layer "In2.Cu")
		(net "M_A_CPU0_SB_DQ<1>")
	)
	(segment
		(start 314.292234 -230.041704)
		(end 313.757056 -230.041704)
		(width 0.18288)
		(layer "In2.Cu")
		(net "M_A_CPU0_SB_DQ<1>")
	)
	(segment
		(start 331.461872 -238.790734)
		(end 331.260958 -238.58982)
		(width 0.088646)
		(layer "In2.Cu")
		(net "M_A_CPU0_SB_DQ<1>")
	)
	(segment
		(start 312.695336 -230.603298)
		(end 311.404 -229.311962)
		(width 0.18288)
		(layer "In2.Cu")
		(net "M_A_CPU0_SB_DQ<1>")
	)
	(segment
		(start 314.850526 -230.391716)
		(end 314.642246 -230.391716)
		(width 0.18288)
		(layer "In2.Cu")
		(net "M_A_CPU0_SB_DQ<1>")
	)
	(segment
		(start 326.67321 -238.58982)
		(end 319.38976 -231.30637)
		(width 0.18288)
		(layer "In2.Cu")
		(net "M_A_CPU0_SB_DQ<1>")
	)
	(segment
		(start 319.38976 -231.30637)
		(end 316.006734 -231.30637)
		(width 0.18288)
		(layer "In2.Cu")
		(net "M_A_CPU0_SB_DQ<1>")
	)
	(segment
		(start 313.757056 -230.041704)
		(end 313.195462 -230.603298)
		(width 0.18288)
		(layer "In2.Cu")
		(net "M_A_CPU0_SB_DQ<1>")
	)
	(segment
		(start 330.699364 -238.58982)
		(end 326.67321 -238.58982)
		(width 0.18288)
		(layer "In2.Cu")
		(net "M_A_CPU0_SB_DQ<1>")
	)
	(segment
		(start 314.642246 -230.391716)
		(end 314.292234 -230.041704)
		(width 0.18288)
		(layer "In2.Cu")
		(net "M_A_CPU0_SB_DQ<1>")
	)
	(segment
		(start 310.473852 -230.273352)
		(end 310.280558 -230.466646)
		(width 0.18288)
		(layer "In2.Cu")
		(net "M_A_CPU0_SB_DQ<1>")
	)
	(segment
		(start 336.55508 -238.225584)
		(end 335.92643 -238.69904)
		(width 0.088646)
		(layer "In2.Cu")
		(net "M_A_CPU0_SB_DQ<1>")
	)
	(segment
		(start 310.666892 -229.311962)
		(end 310.473852 -229.505002)
		(width 0.18288)
		(layer "In2.Cu")
		(net "M_A_CPU0_SB_DQ<1>")
	)
	(segment
		(start 315.594238 -231.135428)
		(end 314.850526 -230.391716)
		(width 0.18288)
		(layer "In2.Cu")
		(net "M_A_CPU0_SB_DQ<1>")
	)
	(segment
		(start 311.404 -229.311962)
		(end 310.666892 -229.311962)
		(width 0.18288)
		(layer "In2.Cu")
		(net "M_A_CPU0_SB_DQ<1>")
	)
	(segment
		(start 316.006734 -231.30637)
		(end 315.594238 -231.135428)
		(width 0.18288)
		(layer "In2.Cu")
		(net "M_A_CPU0_SB_DQ<1>")
	)
	(segment
		(start 335.92643 -238.69904)
		(end 335.898236 -238.715042)
		(width 0.088646)
		(layer "In2.Cu")
		(net "M_A_CPU0_SB_DQ<1>")
	)
	(segment
		(start 310.280558 -230.466646)
		(end 309.992014 -230.466646)
		(width 0.18288)
		(layer "In2.Cu")
		(net "M_A_CPU0_SB_DQ<1>")
	)
	(segment
		(start 331.260958 -238.58982)
		(end 330.699364 -238.58982)
		(width 0.088646)
		(layer "In2.Cu")
		(net "M_A_CPU0_SB_DQ<1>")
	)
	(arc
		(start 333.078836 -238.715042)
		(mid 332.796134 -238.790818)
		(end 332.513432 -238.715042)
		(width 0.088646)
		(layer "In2.Cu")
		(net "M_A_CPU0_SB_DQ<1>")
	)
	(arc
		(start 333.453232 -238.715042)
		(mid 333.266034 -238.664899)
		(end 333.078836 -238.715042)
		(width 0.088646)
		(layer "In2.Cu")
		(net "M_A_CPU0_SB_DQ<1>")
	)
	(arc
		(start 332.139036 -238.715042)
		(mid 332.002667 -238.771484)
		(end 331.856334 -238.790734)
		(width 0.088646)
		(layer "In2.Cu")
		(net "M_A_CPU0_SB_DQ<1>")
	)
	(arc
		(start 332.513432 -238.715042)
		(mid 332.326234 -238.664899)
		(end 332.139036 -238.715042)
		(width 0.088646)
		(layer "In2.Cu")
		(net "M_A_CPU0_SB_DQ<1>")
	)
	(arc
		(start 334.018636 -238.715042)
		(mid 333.735934 -238.790818)
		(end 333.453232 -238.715042)
		(width 0.088646)
		(layer "In2.Cu")
		(net "M_A_CPU0_SB_DQ<1>")
	)
	(arc
		(start 334.393032 -238.715042)
		(mid 334.205834 -238.664899)
		(end 334.018636 -238.715042)
		(width 0.088646)
		(layer "In2.Cu")
		(net "M_A_CPU0_SB_DQ<1>")
	)
	(arc
		(start 334.958436 -238.715042)
		(mid 334.675734 -238.790818)
		(end 334.393032 -238.715042)
		(width 0.088646)
		(layer "In2.Cu")
		(net "M_A_CPU0_SB_DQ<1>")
	)
	(arc
		(start 335.898236 -238.715042)
		(mid 335.615534 -238.790818)
		(end 335.332832 -238.715042)
		(width 0.088646)
		(layer "In2.Cu")
		(net "M_A_CPU0_SB_DQ<1>")
	)
	(arc
		(start 335.332832 -238.715042)
		(mid 335.145634 -238.664899)
		(end 334.958436 -238.715042)
		(width 0.088646)
		(layer "In2.Cu")
		(net "M_A_CPU0_SB_DQ<1>")
	)
	(segment
		(start 333.959454 -231.033066)
		(end 333.784956 -231.207564)
		(width 0.088646)
		(layer "F.Cu")
		(net "M_A_CPU0_SB_DQ<19>")
	)
	(segment
		(start 335.14538 -231.436418)
		(end 335.249012 -231.332786)
		(width 0.088646)
		(layer "F.Cu")
		(net "M_A_CPU0_SB_DQ<19>")
	)
	(segment
		(start 325.586852 -223.502982)
		(end 325.586852 -217.553794)
		(width 0.1016)
		(layer "F.Cu")
		(net "M_A_CPU0_SB_DQ<19>")
	)
	(segment
		(start 325.017384 -216.985088)
		(end 324.922134 -216.889838)
		(width 0.1016)
		(layer "F.Cu")
		(net "M_A_CPU0_SB_DQ<19>")
	)
	(segment
		(start 333.658972 -231.207564)
		(end 333.484474 -231.033066)
		(width 0.088646)
		(layer "F.Cu")
		(net "M_A_CPU0_SB_DQ<19>")
	)
	(segment
		(start 311.142634 -210.916774)
		(end 312.987182 -210.916774)
		(width 0.20066)
		(layer "F.Cu")
		(net "M_A_CPU0_SB_DQ<19>")
	)
	(segment
		(start 319.185798 -211.437474)
		(end 319.185798 -211.153502)
		(width 0.20066)
		(layer "F.Cu")
		(net "M_A_CPU0_SB_DQ<19>")
	)
	(segment
		(start 327.192132 -225.108262)
		(end 325.586852 -223.502982)
		(width 0.1016)
		(layer "F.Cu")
		(net "M_A_CPU0_SB_DQ<19>")
	)
	(segment
		(start 335.627726 -231.332786)
		(end 335.675732 -231.28478)
		(width 0.088646)
		(layer "F.Cu")
		(net "M_A_CPU0_SB_DQ<19>")
	)
	(segment
		(start 335.675732 -231.28478)
		(end 335.675732 -231.090724)
		(width 0.088646)
		(layer "F.Cu")
		(net "M_A_CPU0_SB_DQ<19>")
	)
	(segment
		(start 307.80736 -211.35721)
		(end 307.822854 -211.341716)
		(width 0.101854)
		(layer "F.Cu")
		(net "M_A_CPU0_SB_DQ<19>")
	)
	(segment
		(start 331.46111 -231.293416)
		(end 331.23759 -231.293416)
		(width 0.1016)
		(layer "F.Cu")
		(net "M_A_CPU0_SB_DQ<19>")
	)
	(segment
		(start 319.04686 -212.582252)
		(end 318.762888 -212.582252)
		(width 0.20066)
		(layer "F.Cu")
		(net "M_A_CPU0_SB_DQ<19>")
	)
	(segment
		(start 307.419248 -211.35721)
		(end 307.76291 -211.35721)
		(width 0.20066)
		(layer "F.Cu")
		(net "M_A_CPU0_SB_DQ<19>")
	)
	(segment
		(start 305.443382 -210.916774)
		(end 306.978812 -210.916774)
		(width 0.20066)
		(layer "F.Cu")
		(net "M_A_CPU0_SB_DQ<19>")
	)
	(segment
		(start 335.675732 -231.090724)
		(end 335.588102 -231.003094)
		(width 0.088646)
		(layer "F.Cu")
		(net "M_A_CPU0_SB_DQ<19>")
	)
	(segment
		(start 306.978812 -210.916774)
		(end 307.419248 -211.35721)
		(width 0.20066)
		(layer "F.Cu")
		(net "M_A_CPU0_SB_DQ<19>")
	)
	(segment
		(start 318.54394 -212.079332)
		(end 319.185798 -211.437474)
		(width 0.20066)
		(layer "F.Cu")
		(net "M_A_CPU0_SB_DQ<19>")
	)
	(segment
		(start 333.784956 -231.207564)
		(end 333.658972 -231.207564)
		(width 0.088646)
		(layer "F.Cu")
		(net "M_A_CPU0_SB_DQ<19>")
	)
	(segment
		(start 332.881224 -231.221534)
		(end 332.108048 -231.221534)
		(width 0.088646)
		(layer "F.Cu")
		(net "M_A_CPU0_SB_DQ<19>")
	)
	(segment
		(start 319.688718 -211.940394)
		(end 319.04686 -212.582252)
		(width 0.20066)
		(layer "F.Cu")
		(net "M_A_CPU0_SB_DQ<19>")
	)
	(segment
		(start 310.088026 -211.341716)
		(end 310.366156 -211.341716)
		(width 0.20066)
		(layer "F.Cu")
		(net "M_A_CPU0_SB_DQ<19>")
	)
	(segment
		(start 319.97269 -211.940394)
		(end 319.688718 -211.940394)
		(width 0.20066)
		(layer "F.Cu")
		(net "M_A_CPU0_SB_DQ<19>")
	)
	(segment
		(start 318.762888 -212.582252)
		(end 318.54394 -212.363304)
		(width 0.20066)
		(layer "F.Cu")
		(net "M_A_CPU0_SB_DQ<19>")
	)
	(segment
		(start 333.484474 -231.033066)
		(end 333.377286 -231.033066)
		(width 0.088646)
		(layer "F.Cu")
		(net "M_A_CPU0_SB_DQ<19>")
	)
	(segment
		(start 333.084678 -231.108758)
		(end 332.881224 -231.221534)
		(width 0.088646)
		(layer "F.Cu")
		(net "M_A_CPU0_SB_DQ<19>")
	)
	(segment
		(start 318.94907 -210.916774)
		(end 312.987182 -210.916774)
		(width 0.20066)
		(layer "F.Cu")
		(net "M_A_CPU0_SB_DQ<19>")
	)
	(segment
		(start 335.249012 -231.332786)
		(end 335.627726 -231.332786)
		(width 0.088646)
		(layer "F.Cu")
		(net "M_A_CPU0_SB_DQ<19>")
	)
	(segment
		(start 310.366156 -211.341716)
		(end 310.481472 -211.2264)
		(width 0.20066)
		(layer "F.Cu")
		(net "M_A_CPU0_SB_DQ<19>")
	)
	(segment
		(start 307.822854 -211.341716)
		(end 310.031892 -211.341716)
		(width 0.1016)
		(layer "F.Cu")
		(net "M_A_CPU0_SB_DQ<19>")
	)
	(segment
		(start 310.481472 -210.888834)
		(end 310.662828 -210.707478)
		(width 0.20066)
		(layer "F.Cu")
		(net "M_A_CPU0_SB_DQ<19>")
	)
	(segment
		(start 331.23759 -231.293416)
		(end 327.192132 -227.247958)
		(width 0.1016)
		(layer "F.Cu")
		(net "M_A_CPU0_SB_DQ<19>")
	)
	(segment
		(start 334.957674 -231.11206)
		(end 334.94726 -231.118156)
		(width 0.088646)
		(layer "F.Cu")
		(net "M_A_CPU0_SB_DQ<19>")
	)
	(segment
		(start 335.588102 -231.003094)
		(end 335.359756 -231.003094)
		(width 0.088646)
		(layer "F.Cu")
		(net "M_A_CPU0_SB_DQ<19>")
	)
	(segment
		(start 310.481472 -211.2264)
		(end 310.481472 -210.888834)
		(width 0.20066)
		(layer "F.Cu")
		(net "M_A_CPU0_SB_DQ<19>")
	)
	(segment
		(start 334.097884 -231.033066)
		(end 333.959454 -231.033066)
		(width 0.088646)
		(layer "F.Cu")
		(net "M_A_CPU0_SB_DQ<19>")
	)
	(segment
		(start 310.031892 -211.341716)
		(end 310.088026 -211.341716)
		(width 0.101854)
		(layer "F.Cu")
		(net "M_A_CPU0_SB_DQ<19>")
	)
	(segment
		(start 327.192132 -227.247958)
		(end 327.192132 -225.108262)
		(width 0.1016)
		(layer "F.Cu")
		(net "M_A_CPU0_SB_DQ<19>")
	)
	(segment
		(start 332.108048 -231.221534)
		(end 332.036166 -231.293416)
		(width 0.088646)
		(layer "F.Cu")
		(net "M_A_CPU0_SB_DQ<19>")
	)
	(segment
		(start 310.662828 -210.707478)
		(end 310.933338 -210.707478)
		(width 0.20066)
		(layer "F.Cu")
		(net "M_A_CPU0_SB_DQ<19>")
	)
	(segment
		(start 324.922134 -216.889838)
		(end 319.97269 -211.940394)
		(width 0.20066)
		(layer "F.Cu")
		(net "M_A_CPU0_SB_DQ<19>")
	)
	(segment
		(start 307.76291 -211.35721)
		(end 307.80736 -211.35721)
		(width 0.101854)
		(layer "F.Cu")
		(net "M_A_CPU0_SB_DQ<19>")
	)
	(segment
		(start 319.185798 -211.153502)
		(end 318.94907 -210.916774)
		(width 0.20066)
		(layer "F.Cu")
		(net "M_A_CPU0_SB_DQ<19>")
	)
	(segment
		(start 332.036166 -231.293416)
		(end 331.46111 -231.293416)
		(width 0.088646)
		(layer "F.Cu")
		(net "M_A_CPU0_SB_DQ<19>")
	)
	(segment
		(start 318.54394 -212.363304)
		(end 318.54394 -212.079332)
		(width 0.20066)
		(layer "F.Cu")
		(net "M_A_CPU0_SB_DQ<19>")
	)
	(segment
		(start 325.018146 -216.985088)
		(end 325.017384 -216.985088)
		(width 0.101854)
		(layer "F.Cu")
		(net "M_A_CPU0_SB_DQ<19>")
	)
	(segment
		(start 310.933338 -210.707478)
		(end 311.142634 -210.916774)
		(width 0.20066)
		(layer "F.Cu")
		(net "M_A_CPU0_SB_DQ<19>")
	)
	(segment
		(start 325.586852 -217.553794)
		(end 325.018146 -216.985088)
		(width 0.1016)
		(layer "F.Cu")
		(net "M_A_CPU0_SB_DQ<19>")
	)
	(arc
		(start 334.94726 -231.118156)
		(mid 334.669082 -231.187879)
		(end 334.392524 -231.11206)
		(width 0.088646)
		(layer "F.Cu")
		(net "M_A_CPU0_SB_DQ<19>")
	)
	(arc
		(start 333.377286 -231.033066)
		(mid 333.226161 -231.052286)
		(end 333.084678 -231.108758)
		(width 0.088646)
		(layer "F.Cu")
		(net "M_A_CPU0_SB_DQ<19>")
	)
	(arc
		(start 335.359756 -231.003094)
		(mid 335.151464 -231.030819)
		(end 334.957674 -231.11206)
		(width 0.088646)
		(layer "F.Cu")
		(net "M_A_CPU0_SB_DQ<19>")
	)
	(arc
		(start 334.392524 -231.11206)
		(mid 334.250402 -231.053186)
		(end 334.097884 -231.033066)
		(width 0.088646)
		(layer "F.Cu")
		(net "M_A_CPU0_SB_DQ<19>")
	)
	(segment
		(start 307.836062 -213.041738)
		(end 310.064912 -213.041738)
		(width 0.1016)
		(layer "F.Cu")
		(net "M_A_CPU0_SB_DQ<18>")
	)
	(segment
		(start 310.088026 -213.047072)
		(end 310.48198 -213.047072)
		(width 0.20066)
		(layer "F.Cu")
		(net "M_A_CPU0_SB_DQ<18>")
	)
	(segment
		(start 321.746372 -215.844882)
		(end 321.038982 -216.552272)
		(width 0.20066)
		(layer "F.Cu")
		(net "M_A_CPU0_SB_DQ<18>")
	)
	(segment
		(start 307.822092 -213.055708)
		(end 307.836062 -213.041738)
		(width 0.101854)
		(layer "F.Cu")
		(net "M_A_CPU0_SB_DQ<18>")
	)
	(segment
		(start 313.847734 -212.616796)
		(end 312.987182 -212.616796)
		(width 0.20066)
		(layer "F.Cu")
		(net "M_A_CPU0_SB_DQ<18>")
	)
	(segment
		(start 322.752212 -216.850722)
		(end 322.044822 -217.558112)
		(width 0.20066)
		(layer "F.Cu")
		(net "M_A_CPU0_SB_DQ<18>")
	)
	(segment
		(start 321.038982 -216.552272)
		(end 320.75501 -216.552272)
		(width 0.20066)
		(layer "F.Cu")
		(net "M_A_CPU0_SB_DQ<18>")
	)
	(segment
		(start 314.015628 -212.448902)
		(end 313.847734 -212.616796)
		(width 0.20066)
		(layer "F.Cu")
		(net "M_A_CPU0_SB_DQ<18>")
	)
	(segment
		(start 323.036184 -216.850722)
		(end 322.752212 -216.850722)
		(width 0.20066)
		(layer "F.Cu")
		(net "M_A_CPU0_SB_DQ<18>")
	)
	(segment
		(start 324.50151 -218.316048)
		(end 323.036184 -216.850722)
		(width 0.20066)
		(layer "F.Cu")
		(net "M_A_CPU0_SB_DQ<18>")
	)
	(segment
		(start 312.084974 -212.616796)
		(end 312.987182 -212.616796)
		(width 0.20066)
		(layer "F.Cu")
		(net "M_A_CPU0_SB_DQ<18>")
	)
	(segment
		(start 321.027298 -214.819484)
		(end 319.115186 -214.819484)
		(width 0.20066)
		(layer "F.Cu")
		(net "M_A_CPU0_SB_DQ<18>")
	)
	(segment
		(start 321.541902 -217.339164)
		(end 321.541902 -217.055192)
		(width 0.20066)
		(layer "F.Cu")
		(net "M_A_CPU0_SB_DQ<18>")
	)
	(segment
		(start 310.609996 -212.560916)
		(end 310.736996 -212.433916)
		(width 0.20066)
		(layer "F.Cu")
		(net "M_A_CPU0_SB_DQ<18>")
	)
	(segment
		(start 334.419956 -231.99471)
		(end 334.29829 -231.99471)
		(width 0.088646)
		(layer "F.Cu")
		(net "M_A_CPU0_SB_DQ<18>")
	)
	(segment
		(start 333.000858 -231.70134)
		(end 332.929992 -231.630474)
		(width 0.088646)
		(layer "F.Cu")
		(net "M_A_CPU0_SB_DQ<18>")
	)
	(segment
		(start 321.243452 -215.341962)
		(end 321.243452 -215.035638)
		(width 0.20066)
		(layer "F.Cu")
		(net "M_A_CPU0_SB_DQ<18>")
	)
	(segment
		(start 307.516022 -213.055708)
		(end 307.76291 -213.055708)
		(width 0.20066)
		(layer "F.Cu")
		(net "M_A_CPU0_SB_DQ<18>")
	)
	(segment
		(start 321.76085 -217.558112)
		(end 321.541902 -217.339164)
		(width 0.20066)
		(layer "F.Cu")
		(net "M_A_CPU0_SB_DQ<18>")
	)
	(segment
		(start 332.387448 -231.630474)
		(end 332.108556 -231.909366)
		(width 0.088646)
		(layer "F.Cu")
		(net "M_A_CPU0_SB_DQ<18>")
	)
	(segment
		(start 310.48198 -213.047072)
		(end 310.609996 -212.919056)
		(width 0.20066)
		(layer "F.Cu")
		(net "M_A_CPU0_SB_DQ<18>")
	)
	(segment
		(start 310.070246 -213.047072)
		(end 310.088026 -213.047072)
		(width 0.101854)
		(layer "F.Cu")
		(net "M_A_CPU0_SB_DQ<18>")
	)
	(segment
		(start 334.235044 -232.057956)
		(end 334.05572 -232.057956)
		(width 0.088646)
		(layer "F.Cu")
		(net "M_A_CPU0_SB_DQ<18>")
	)
	(segment
		(start 322.249292 -216.347802)
		(end 322.249292 -216.06383)
		(width 0.20066)
		(layer "F.Cu")
		(net "M_A_CPU0_SB_DQ<18>")
	)
	(segment
		(start 321.541902 -217.055192)
		(end 322.249292 -216.347802)
		(width 0.20066)
		(layer "F.Cu")
		(net "M_A_CPU0_SB_DQ<18>")
	)
	(segment
		(start 333.46898 -231.81183)
		(end 333.269844 -231.81183)
		(width 0.088646)
		(layer "F.Cu")
		(net "M_A_CPU0_SB_DQ<18>")
	)
	(segment
		(start 332.929992 -231.630474)
		(end 332.387448 -231.630474)
		(width 0.088646)
		(layer "F.Cu")
		(net "M_A_CPU0_SB_DQ<18>")
	)
	(segment
		(start 320.75501 -216.552272)
		(end 320.536062 -216.333324)
		(width 0.20066)
		(layer "F.Cu")
		(net "M_A_CPU0_SB_DQ<18>")
	)
	(segment
		(start 330.990956 -231.909366)
		(end 326.582532 -227.500942)
		(width 0.1016)
		(layer "F.Cu")
		(net "M_A_CPU0_SB_DQ<18>")
	)
	(segment
		(start 319.115186 -214.819484)
		(end 316.744604 -212.448902)
		(width 0.20066)
		(layer "F.Cu")
		(net "M_A_CPU0_SB_DQ<18>")
	)
	(segment
		(start 324.977252 -218.79179)
		(end 324.50151 -218.316048)
		(width 0.1016)
		(layer "F.Cu")
		(net "M_A_CPU0_SB_DQ<18>")
	)
	(segment
		(start 333.802736 -231.628442)
		(end 333.652368 -231.628442)
		(width 0.088646)
		(layer "F.Cu")
		(net "M_A_CPU0_SB_DQ<18>")
	)
	(segment
		(start 333.909416 -231.911652)
		(end 333.909416 -231.735122)
		(width 0.088646)
		(layer "F.Cu")
		(net "M_A_CPU0_SB_DQ<18>")
	)
	(segment
		(start 311.902094 -212.433916)
		(end 312.084974 -212.616796)
		(width 0.20066)
		(layer "F.Cu")
		(net "M_A_CPU0_SB_DQ<18>")
	)
	(segment
		(start 322.030344 -215.844882)
		(end 321.746372 -215.844882)
		(width 0.20066)
		(layer "F.Cu")
		(net "M_A_CPU0_SB_DQ<18>")
	)
	(segment
		(start 320.536062 -216.333324)
		(end 320.536062 -216.049352)
		(width 0.20066)
		(layer "F.Cu")
		(net "M_A_CPU0_SB_DQ<18>")
	)
	(segment
		(start 333.652368 -231.628442)
		(end 333.46898 -231.81183)
		(width 0.088646)
		(layer "F.Cu")
		(net "M_A_CPU0_SB_DQ<18>")
	)
	(segment
		(start 326.582532 -225.361246)
		(end 324.977252 -223.755966)
		(width 0.1016)
		(layer "F.Cu")
		(net "M_A_CPU0_SB_DQ<18>")
	)
	(segment
		(start 333.909416 -231.735122)
		(end 333.802736 -231.628442)
		(width 0.088646)
		(layer "F.Cu")
		(net "M_A_CPU0_SB_DQ<18>")
	)
	(segment
		(start 305.443382 -212.616796)
		(end 307.07711 -212.616796)
		(width 0.20066)
		(layer "F.Cu")
		(net "M_A_CPU0_SB_DQ<18>")
	)
	(segment
		(start 310.736996 -212.433916)
		(end 311.902094 -212.433916)
		(width 0.20066)
		(layer "F.Cu")
		(net "M_A_CPU0_SB_DQ<18>")
	)
	(segment
		(start 332.108556 -231.909366)
		(end 331.46111 -231.909366)
		(width 0.088646)
		(layer "F.Cu")
		(net "M_A_CPU0_SB_DQ<18>")
	)
	(segment
		(start 322.249292 -216.06383)
		(end 322.030344 -215.844882)
		(width 0.20066)
		(layer "F.Cu")
		(net "M_A_CPU0_SB_DQ<18>")
	)
	(segment
		(start 334.05572 -232.057956)
		(end 333.909416 -231.911652)
		(width 0.088646)
		(layer "F.Cu")
		(net "M_A_CPU0_SB_DQ<18>")
	)
	(segment
		(start 324.977252 -223.755966)
		(end 324.977252 -218.79179)
		(width 0.1016)
		(layer "F.Cu")
		(net "M_A_CPU0_SB_DQ<18>")
	)
	(segment
		(start 307.76291 -213.055708)
		(end 307.822092 -213.055708)
		(width 0.101854)
		(layer "F.Cu")
		(net "M_A_CPU0_SB_DQ<18>")
	)
	(segment
		(start 307.07711 -212.616796)
		(end 307.516022 -213.055708)
		(width 0.20066)
		(layer "F.Cu")
		(net "M_A_CPU0_SB_DQ<18>")
	)
	(segment
		(start 326.582532 -227.500942)
		(end 326.582532 -225.361246)
		(width 0.1016)
		(layer "F.Cu")
		(net "M_A_CPU0_SB_DQ<18>")
	)
	(segment
		(start 321.243452 -215.035638)
		(end 321.027298 -214.819484)
		(width 0.20066)
		(layer "F.Cu")
		(net "M_A_CPU0_SB_DQ<18>")
	)
	(segment
		(start 331.46111 -231.909366)
		(end 330.990956 -231.909366)
		(width 0.1016)
		(layer "F.Cu")
		(net "M_A_CPU0_SB_DQ<18>")
	)
	(segment
		(start 316.744604 -212.448902)
		(end 314.015628 -212.448902)
		(width 0.20066)
		(layer "F.Cu")
		(net "M_A_CPU0_SB_DQ<18>")
	)
	(segment
		(start 322.044822 -217.558112)
		(end 321.76085 -217.558112)
		(width 0.20066)
		(layer "F.Cu")
		(net "M_A_CPU0_SB_DQ<18>")
	)
	(segment
		(start 320.536062 -216.049352)
		(end 321.243452 -215.341962)
		(width 0.20066)
		(layer "F.Cu")
		(net "M_A_CPU0_SB_DQ<18>")
	)
	(segment
		(start 334.29829 -231.99471)
		(end 334.235044 -232.057956)
		(width 0.088646)
		(layer "F.Cu")
		(net "M_A_CPU0_SB_DQ<18>")
	)
	(segment
		(start 310.609996 -212.919056)
		(end 310.609996 -212.560916)
		(width 0.20066)
		(layer "F.Cu")
		(net "M_A_CPU0_SB_DQ<18>")
	)
	(segment
		(start 334.675734 -232.250488)
		(end 334.419956 -231.99471)
		(width 0.088646)
		(layer "F.Cu")
		(net "M_A_CPU0_SB_DQ<18>")
	)
	(segment
		(start 310.064912 -213.041738)
		(end 310.070246 -213.047072)
		(width 0.101854)
		(layer "F.Cu")
		(net "M_A_CPU0_SB_DQ<18>")
	)
	(arc
		(start 333.078582 -231.760776)
		(mid 333.037773 -231.733604)
		(end 333.000858 -231.70134)
		(width 0.088646)
		(layer "F.Cu")
		(net "M_A_CPU0_SB_DQ<18>")
	)
	(arc
		(start 333.269844 -231.81183)
		(mid 333.170869 -231.798839)
		(end 333.078582 -231.760776)
		(width 0.088646)
		(layer "F.Cu")
		(net "M_A_CPU0_SB_DQ<18>")
	)
	(segment
		(start 303.523396 -212.027008)
		(end 303.523396 -211.496148)
		(width 0.20066)
		(layer "F.Cu")
		(net "M_A_CPU0_SB_DQ<17>")
	)
	(segment
		(start 319.199514 -213.418166)
		(end 319.71742 -212.90026)
		(width 0.20066)
		(layer "F.Cu")
		(net "M_A_CPU0_SB_DQ<17>")
	)
	(segment
		(start 314.094876 -211.341716)
		(end 314.10148 -211.335112)
		(width 0.101854)
		(layer "F.Cu")
		(net "M_A_CPU0_SB_DQ<17>")
	)
	(segment
		(start 326.887332 -227.37445)
		(end 331.111352 -231.59847)
		(width 0.1016)
		(layer "F.Cu")
		(net "M_A_CPU0_SB_DQ<17>")
	)
	(segment
		(start 319.71742 -212.90026)
		(end 320.001392 -212.90026)
		(width 0.20066)
		(layer "F.Cu")
		(net "M_A_CPU0_SB_DQ<17>")
	)
	(segment
		(start 301.343314 -211.766658)
		(end 302.46447 -211.766658)
		(width 0.20066)
		(layer "F.Cu")
		(net "M_A_CPU0_SB_DQ<17>")
	)
	(segment
		(start 313.843416 -211.341716)
		(end 314.094876 -211.341716)
		(width 0.101854)
		(layer "F.Cu")
		(net "M_A_CPU0_SB_DQ<17>")
	)
	(segment
		(start 320.449448 -214.179912)
		(end 320.691256 -213.938104)
		(width 0.20066)
		(layer "F.Cu")
		(net "M_A_CPU0_SB_DQ<17>")
	)
	(segment
		(start 319.946528 -213.676992)
		(end 319.946528 -213.960964)
		(width 0.20066)
		(layer "F.Cu")
		(net "M_A_CPU0_SB_DQ<17>")
	)
	(segment
		(start 331.46111 -231.59847)
		(end 332.047596 -231.59847)
		(width 0.088646)
		(layer "F.Cu")
		(net "M_A_CPU0_SB_DQ<17>")
	)
	(segment
		(start 311.661556 -211.33054)
		(end 311.96788 -211.33054)
		(width 0.20066)
		(layer "F.Cu")
		(net "M_A_CPU0_SB_DQ<17>")
	)
	(segment
		(start 316.997842 -211.73821)
		(end 318.677798 -213.418166)
		(width 0.20066)
		(layer "F.Cu")
		(net "M_A_CPU0_SB_DQ<17>")
	)
	(segment
		(start 320.22034 -213.40318)
		(end 319.946528 -213.676992)
		(width 0.20066)
		(layer "F.Cu")
		(net "M_A_CPU0_SB_DQ<17>")
	)
	(segment
		(start 320.22034 -213.119208)
		(end 320.22034 -213.40318)
		(width 0.20066)
		(layer "F.Cu")
		(net "M_A_CPU0_SB_DQ<17>")
	)
	(segment
		(start 310.413908 -212.088476)
		(end 310.73598 -211.766404)
		(width 0.20066)
		(layer "F.Cu")
		(net "M_A_CPU0_SB_DQ<17>")
	)
	(segment
		(start 314.302394 -211.335112)
		(end 314.705492 -211.73821)
		(width 0.20066)
		(layer "F.Cu")
		(net "M_A_CPU0_SB_DQ<17>")
	)
	(segment
		(start 309.381398 -211.766404)
		(end 309.70347 -212.088476)
		(width 0.20066)
		(layer "F.Cu")
		(net "M_A_CPU0_SB_DQ<17>")
	)
	(segment
		(start 314.705492 -211.73821)
		(end 316.997842 -211.73821)
		(width 0.20066)
		(layer "F.Cu")
		(net "M_A_CPU0_SB_DQ<17>")
	)
	(segment
		(start 325.282052 -218.169744)
		(end 325.282052 -223.629474)
		(width 0.1016)
		(layer "F.Cu")
		(net "M_A_CPU0_SB_DQ<17>")
	)
	(segment
		(start 332.209648 -231.436418)
		(end 333.26578 -231.436418)
		(width 0.088646)
		(layer "F.Cu")
		(net "M_A_CPU0_SB_DQ<17>")
	)
	(segment
		(start 320.001392 -212.90026)
		(end 320.22034 -213.119208)
		(width 0.20066)
		(layer "F.Cu")
		(net "M_A_CPU0_SB_DQ<17>")
	)
	(segment
		(start 303.683924 -211.33562)
		(end 304.319178 -211.33562)
		(width 0.20066)
		(layer "F.Cu")
		(net "M_A_CPU0_SB_DQ<17>")
	)
	(segment
		(start 311.225692 -211.766404)
		(end 311.661556 -211.33054)
		(width 0.20066)
		(layer "F.Cu")
		(net "M_A_CPU0_SB_DQ<17>")
	)
	(segment
		(start 307.205888 -211.766658)
		(end 308.887114 -211.766658)
		(width 0.20066)
		(layer "F.Cu")
		(net "M_A_CPU0_SB_DQ<17>")
	)
	(segment
		(start 303.400968 -212.149436)
		(end 303.523396 -212.027008)
		(width 0.20066)
		(layer "F.Cu")
		(net "M_A_CPU0_SB_DQ<17>")
	)
	(segment
		(start 304.33899 -211.341716)
		(end 306.289202 -211.341716)
		(width 0.1016)
		(layer "F.Cu")
		(net "M_A_CPU0_SB_DQ<17>")
	)
	(segment
		(start 320.165476 -214.179912)
		(end 320.449448 -214.179912)
		(width 0.20066)
		(layer "F.Cu")
		(net "M_A_CPU0_SB_DQ<17>")
	)
	(segment
		(start 325.09714 -217.984832)
		(end 325.282052 -218.169744)
		(width 0.1016)
		(layer "F.Cu")
		(net "M_A_CPU0_SB_DQ<17>")
	)
	(segment
		(start 310.73598 -211.766404)
		(end 311.225692 -211.766404)
		(width 0.20066)
		(layer "F.Cu")
		(net "M_A_CPU0_SB_DQ<17>")
	)
	(segment
		(start 308.887114 -211.766658)
		(end 309.381144 -211.766658)
		(width 0.20066)
		(layer "F.Cu")
		(net "M_A_CPU0_SB_DQ<17>")
	)
	(segment
		(start 303.523396 -211.496148)
		(end 303.683924 -211.33562)
		(width 0.20066)
		(layer "F.Cu")
		(net "M_A_CPU0_SB_DQ<17>")
	)
	(segment
		(start 311.992264 -211.33054)
		(end 312.00344 -211.341716)
		(width 0.101854)
		(layer "F.Cu")
		(net "M_A_CPU0_SB_DQ<17>")
	)
	(segment
		(start 326.887332 -225.234754)
		(end 326.887332 -227.37445)
		(width 0.1016)
		(layer "F.Cu")
		(net "M_A_CPU0_SB_DQ<17>")
	)
	(segment
		(start 309.70347 -212.088476)
		(end 310.413908 -212.088476)
		(width 0.20066)
		(layer "F.Cu")
		(net "M_A_CPU0_SB_DQ<17>")
	)
	(segment
		(start 325.282052 -223.629474)
		(end 326.887332 -225.234754)
		(width 0.1016)
		(layer "F.Cu")
		(net "M_A_CPU0_SB_DQ<17>")
	)
	(segment
		(start 311.96788 -211.33054)
		(end 311.992264 -211.33054)
		(width 0.101854)
		(layer "F.Cu")
		(net "M_A_CPU0_SB_DQ<17>")
	)
	(segment
		(start 331.111352 -231.59847)
		(end 331.46111 -231.59847)
		(width 0.1016)
		(layer "F.Cu")
		(net "M_A_CPU0_SB_DQ<17>")
	)
	(segment
		(start 320.691256 -213.938104)
		(end 321.050412 -213.938104)
		(width 0.20066)
		(layer "F.Cu")
		(net "M_A_CPU0_SB_DQ<17>")
	)
	(segment
		(start 321.050412 -213.938104)
		(end 325.09714 -217.984832)
		(width 0.20066)
		(layer "F.Cu")
		(net "M_A_CPU0_SB_DQ<17>")
	)
	(segment
		(start 314.10148 -211.335112)
		(end 314.302394 -211.335112)
		(width 0.20066)
		(layer "F.Cu")
		(net "M_A_CPU0_SB_DQ<17>")
	)
	(segment
		(start 309.381144 -211.766658)
		(end 309.381398 -211.766404)
		(width 0.20066)
		(layer "F.Cu")
		(net "M_A_CPU0_SB_DQ<17>")
	)
	(segment
		(start 306.289202 -211.341716)
		(end 306.644294 -211.341716)
		(width 0.101854)
		(layer "F.Cu")
		(net "M_A_CPU0_SB_DQ<17>")
	)
	(segment
		(start 304.319178 -211.33562)
		(end 304.33899 -211.341716)
		(width 0.1016)
		(layer "F.Cu")
		(net "M_A_CPU0_SB_DQ<17>")
	)
	(segment
		(start 318.677798 -213.418166)
		(end 319.199514 -213.418166)
		(width 0.20066)
		(layer "F.Cu")
		(net "M_A_CPU0_SB_DQ<17>")
	)
	(segment
		(start 306.644294 -211.341716)
		(end 306.780946 -211.341716)
		(width 0.20066)
		(layer "F.Cu")
		(net "M_A_CPU0_SB_DQ<17>")
	)
	(segment
		(start 312.00344 -211.341716)
		(end 313.843416 -211.341716)
		(width 0.1016)
		(layer "F.Cu")
		(net "M_A_CPU0_SB_DQ<17>")
	)
	(segment
		(start 302.46447 -211.766658)
		(end 302.847248 -212.149436)
		(width 0.20066)
		(layer "F.Cu")
		(net "M_A_CPU0_SB_DQ<17>")
	)
	(segment
		(start 319.946528 -213.960964)
		(end 320.165476 -214.179912)
		(width 0.20066)
		(layer "F.Cu")
		(net "M_A_CPU0_SB_DQ<17>")
	)
	(segment
		(start 332.047596 -231.59847)
		(end 332.209648 -231.436418)
		(width 0.088646)
		(layer "F.Cu")
		(net "M_A_CPU0_SB_DQ<17>")
	)
	(segment
		(start 302.847248 -212.149436)
		(end 303.400968 -212.149436)
		(width 0.20066)
		(layer "F.Cu")
		(net "M_A_CPU0_SB_DQ<17>")
	)
	(segment
		(start 306.780946 -211.341716)
		(end 307.205888 -211.766658)
		(width 0.20066)
		(layer "F.Cu")
		(net "M_A_CPU0_SB_DQ<17>")
	)
	(segment
		(start 307.272944 -213.46668)
		(end 308.887114 -213.46668)
		(width 0.20066)
		(layer "F.Cu")
		(net "M_A_CPU0_SB_DQ<16>")
	)
	(segment
		(start 303.334928 -213.672674)
		(end 303.523396 -213.484206)
		(width 0.20066)
		(layer "F.Cu")
		(net "M_A_CPU0_SB_DQ<16>")
	)
	(segment
		(start 323.351144 -218.07043)
		(end 323.132196 -217.851482)
		(width 0.20066)
		(layer "F.Cu")
		(net "M_A_CPU0_SB_DQ<16>")
	)
	(segment
		(start 326.277732 -227.627434)
		(end 326.277732 -225.487738)
		(width 0.1016)
		(layer "F.Cu")
		(net "M_A_CPU0_SB_DQ<16>")
	)
	(segment
		(start 314.279534 -213.03107)
		(end 314.12688 -213.03107)
		(width 0.20066)
		(layer "F.Cu")
		(net "M_A_CPU0_SB_DQ<16>")
	)
	(segment
		(start 303.523396 -213.19617)
		(end 303.71923 -213.000336)
		(width 0.20066)
		(layer "F.Cu")
		(net "M_A_CPU0_SB_DQ<16>")
	)
	(segment
		(start 332.438248 -231.876092)
		(end 332.055724 -232.258616)
		(width 0.088646)
		(layer "F.Cu")
		(net "M_A_CPU0_SB_DQ<16>")
	)
	(segment
		(start 303.523396 -213.484206)
		(end 303.523396 -213.19617)
		(width 0.20066)
		(layer "F.Cu")
		(net "M_A_CPU0_SB_DQ<16>")
	)
	(segment
		(start 324.672452 -219.81668)
		(end 324.342506 -219.486734)
		(width 0.1016)
		(layer "F.Cu")
		(net "M_A_CPU0_SB_DQ<16>")
	)
	(segment
		(start 304.319178 -213.000336)
		(end 304.34788 -213.000336)
		(width 0.101854)
		(layer "F.Cu")
		(net "M_A_CPU0_SB_DQ<16>")
	)
	(segment
		(start 304.415444 -213.000336)
		(end 304.550826 -213.041738)
		(width 0.1016)
		(layer "F.Cu")
		(net "M_A_CPU0_SB_DQ<16>")
	)
	(segment
		(start 332.796134 -231.876092)
		(end 332.438248 -231.876092)
		(width 0.088646)
		(layer "F.Cu")
		(net "M_A_CPU0_SB_DQ<16>")
	)
	(segment
		(start 322.848224 -217.851482)
		(end 322.140834 -218.558872)
		(width 0.20066)
		(layer "F.Cu")
		(net "M_A_CPU0_SB_DQ<16>")
	)
	(segment
		(start 306.644294 -213.022942)
		(end 306.829206 -213.022942)
		(width 0.20066)
		(layer "F.Cu")
		(net "M_A_CPU0_SB_DQ<16>")
	)
	(segment
		(start 321.856862 -218.558872)
		(end 316.473586 -213.175596)
		(width 0.20066)
		(layer "F.Cu")
		(net "M_A_CPU0_SB_DQ<16>")
	)
	(segment
		(start 316.473586 -213.175596)
		(end 314.42406 -213.175596)
		(width 0.20066)
		(layer "F.Cu")
		(net "M_A_CPU0_SB_DQ<16>")
	)
	(segment
		(start 331.461364 -232.258616)
		(end 330.908914 -232.258616)
		(width 0.1016)
		(layer "F.Cu")
		(net "M_A_CPU0_SB_DQ<16>")
	)
	(segment
		(start 311.91708 -213.028022)
		(end 311.20588 -213.028022)
		(width 0.20066)
		(layer "F.Cu")
		(net "M_A_CPU0_SB_DQ<16>")
	)
	(segment
		(start 304.550826 -213.041738)
		(end 306.289202 -213.041738)
		(width 0.1016)
		(layer "F.Cu")
		(net "M_A_CPU0_SB_DQ<16>")
	)
	(segment
		(start 314.084716 -213.041738)
		(end 312.12536 -213.041738)
		(width 0.1016)
		(layer "F.Cu")
		(net "M_A_CPU0_SB_DQ<16>")
	)
	(segment
		(start 323.351144 -218.354402)
		(end 323.351144 -218.07043)
		(width 0.20066)
		(layer "F.Cu")
		(net "M_A_CPU0_SB_DQ<16>")
	)
	(segment
		(start 314.087256 -213.039198)
		(end 314.084716 -213.041738)
		(width 0.101854)
		(layer "F.Cu")
		(net "M_A_CPU0_SB_DQ<16>")
	)
	(segment
		(start 303.71923 -213.000336)
		(end 304.319178 -213.000336)
		(width 0.20066)
		(layer "F.Cu")
		(net "M_A_CPU0_SB_DQ<16>")
	)
	(segment
		(start 306.829206 -213.022942)
		(end 307.272944 -213.46668)
		(width 0.20066)
		(layer "F.Cu")
		(net "M_A_CPU0_SB_DQ<16>")
	)
	(segment
		(start 332.055724 -232.258616)
		(end 331.461364 -232.258616)
		(width 0.088646)
		(layer "F.Cu")
		(net "M_A_CPU0_SB_DQ<16>")
	)
	(segment
		(start 310.767222 -213.46668)
		(end 308.887114 -213.46668)
		(width 0.20066)
		(layer "F.Cu")
		(net "M_A_CPU0_SB_DQ<16>")
	)
	(segment
		(start 333.735934 -232.250488)
		(end 333.293974 -232.108248)
		(width 0.088646)
		(layer "F.Cu")
		(net "M_A_CPU0_SB_DQ<16>")
	)
	(segment
		(start 314.42406 -213.175596)
		(end 314.279534 -213.03107)
		(width 0.20066)
		(layer "F.Cu")
		(net "M_A_CPU0_SB_DQ<16>")
	)
	(segment
		(start 324.342506 -219.486734)
		(end 323.510402 -219.486734)
		(width 0.1016)
		(layer "F.Cu")
		(net "M_A_CPU0_SB_DQ<16>")
	)
	(segment
		(start 330.908914 -232.258616)
		(end 326.277732 -227.627434)
		(width 0.1016)
		(layer "F.Cu")
		(net "M_A_CPU0_SB_DQ<16>")
	)
	(segment
		(start 324.672452 -223.882458)
		(end 324.672452 -219.81668)
		(width 0.1016)
		(layer "F.Cu")
		(net "M_A_CPU0_SB_DQ<16>")
	)
	(segment
		(start 323.510402 -219.486734)
		(end 322.784724 -219.486734)
		(width 0.20066)
		(layer "F.Cu")
		(net "M_A_CPU0_SB_DQ<16>")
	)
	(segment
		(start 322.643754 -219.345764)
		(end 322.643754 -219.061792)
		(width 0.20066)
		(layer "F.Cu")
		(net "M_A_CPU0_SB_DQ<16>")
	)
	(segment
		(start 304.34788 -213.000336)
		(end 304.415444 -213.000336)
		(width 0.1016)
		(layer "F.Cu")
		(net "M_A_CPU0_SB_DQ<16>")
	)
	(segment
		(start 322.643754 -219.061792)
		(end 323.351144 -218.354402)
		(width 0.20066)
		(layer "F.Cu")
		(net "M_A_CPU0_SB_DQ<16>")
	)
	(segment
		(start 314.12688 -213.03107)
		(end 314.08751 -213.03107)
		(width 0.101854)
		(layer "F.Cu")
		(net "M_A_CPU0_SB_DQ<16>")
	)
	(segment
		(start 306.289202 -213.041738)
		(end 306.354734 -213.022942)
		(width 0.1016)
		(layer "F.Cu")
		(net "M_A_CPU0_SB_DQ<16>")
	)
	(segment
		(start 306.354734 -213.022942)
		(end 306.644294 -213.022942)
		(width 0.101854)
		(layer "F.Cu")
		(net "M_A_CPU0_SB_DQ<16>")
	)
	(segment
		(start 323.132196 -217.851482)
		(end 322.848224 -217.851482)
		(width 0.20066)
		(layer "F.Cu")
		(net "M_A_CPU0_SB_DQ<16>")
	)
	(segment
		(start 302.653446 -213.46668)
		(end 302.85944 -213.672674)
		(width 0.20066)
		(layer "F.Cu")
		(net "M_A_CPU0_SB_DQ<16>")
	)
	(segment
		(start 314.08751 -213.03107)
		(end 314.087256 -213.031324)
		(width 0.101854)
		(layer "F.Cu")
		(net "M_A_CPU0_SB_DQ<16>")
	)
	(segment
		(start 322.140834 -218.558872)
		(end 321.856862 -218.558872)
		(width 0.20066)
		(layer "F.Cu")
		(net "M_A_CPU0_SB_DQ<16>")
	)
	(segment
		(start 333.293974 -232.108248)
		(end 332.983332 -231.92613)
		(width 0.088646)
		(layer "F.Cu")
		(net "M_A_CPU0_SB_DQ<16>")
	)
	(segment
		(start 322.784724 -219.486734)
		(end 322.643754 -219.345764)
		(width 0.20066)
		(layer "F.Cu")
		(net "M_A_CPU0_SB_DQ<16>")
	)
	(segment
		(start 314.087256 -213.031324)
		(end 314.087256 -213.039198)
		(width 0.101854)
		(layer "F.Cu")
		(net "M_A_CPU0_SB_DQ<16>")
	)
	(segment
		(start 302.85944 -213.672674)
		(end 303.334928 -213.672674)
		(width 0.20066)
		(layer "F.Cu")
		(net "M_A_CPU0_SB_DQ<16>")
	)
	(segment
		(start 311.930796 -213.041738)
		(end 311.91708 -213.028022)
		(width 0.101854)
		(layer "F.Cu")
		(net "M_A_CPU0_SB_DQ<16>")
	)
	(segment
		(start 326.277732 -225.487738)
		(end 324.672452 -223.882458)
		(width 0.1016)
		(layer "F.Cu")
		(net "M_A_CPU0_SB_DQ<16>")
	)
	(segment
		(start 301.343314 -213.46668)
		(end 302.653446 -213.46668)
		(width 0.20066)
		(layer "F.Cu")
		(net "M_A_CPU0_SB_DQ<16>")
	)
	(segment
		(start 311.20588 -213.028022)
		(end 310.767222 -213.46668)
		(width 0.20066)
		(layer "F.Cu")
		(net "M_A_CPU0_SB_DQ<16>")
	)
	(segment
		(start 312.12536 -213.041738)
		(end 311.930796 -213.041738)
		(width 0.101854)
		(layer "F.Cu")
		(net "M_A_CPU0_SB_DQ<16>")
	)
	(arc
		(start 332.983332 -231.92613)
		(mid 332.893025 -231.888801)
		(end 332.796134 -231.876092)
		(width 0.088646)
		(layer "F.Cu")
		(net "M_A_CPU0_SB_DQ<16>")
	)
	(segment
		(start 322.495926 -224.744026)
		(end 322.275454 -224.523554)
		(width 0.20066)
		(layer "F.Cu")
		(net "M_A_CPU0_SB_DQ<15>")
	)
	(segment
		(start 309.804054 -214.741506)
		(end 310.088026 -214.741506)
		(width 0.101854)
		(layer "F.Cu")
		(net "M_A_CPU0_SB_DQ<15>")
	)
	(segment
		(start 307.791358 -214.741506)
		(end 307.80228 -214.741506)
		(width 0.101854)
		(layer "F.Cu")
		(net "M_A_CPU0_SB_DQ<15>")
	)
	(segment
		(start 310.736996 -214.133684)
		(end 311.873138 -214.133684)
		(width 0.20066)
		(layer "F.Cu")
		(net "M_A_CPU0_SB_DQ<15>")
	)
	(segment
		(start 325.403464 -227.601272)
		(end 325.403464 -226.481894)
		(width 0.1016)
		(layer "F.Cu")
		(net "M_A_CPU0_SB_DQ<15>")
	)
	(segment
		(start 333.472536 -233.501946)
		(end 333.45501 -233.501946)
		(width 0.088646)
		(layer "F.Cu")
		(net "M_A_CPU0_SB_DQ<15>")
	)
	(segment
		(start 323.153278 -222.019622)
		(end 323.153278 -221.709742)
		(width 0.20066)
		(layer "F.Cu")
		(net "M_A_CPU0_SB_DQ<15>")
	)
	(segment
		(start 307.482748 -214.756238)
		(end 307.76291 -214.756238)
		(width 0.20066)
		(layer "F.Cu")
		(net "M_A_CPU0_SB_DQ<15>")
	)
	(segment
		(start 310.609996 -214.260684)
		(end 310.736996 -214.133684)
		(width 0.20066)
		(layer "F.Cu")
		(net "M_A_CPU0_SB_DQ<15>")
	)
	(segment
		(start 324.61073 -225.68916)
		(end 323.665596 -224.744026)
		(width 0.20066)
		(layer "F.Cu")
		(net "M_A_CPU0_SB_DQ<15>")
	)
	(segment
		(start 313.50331 -214.316564)
		(end 312.987182 -214.316564)
		(width 0.20066)
		(layer "F.Cu")
		(net "M_A_CPU0_SB_DQ<15>")
	)
	(segment
		(start 322.476114 -221.509082)
		(end 322.275454 -221.308422)
		(width 0.20066)
		(layer "F.Cu")
		(net "M_A_CPU0_SB_DQ<15>")
	)
	(segment
		(start 322.275454 -220.830902)
		(end 315.507878 -214.063326)
		(width 0.20066)
		(layer "F.Cu")
		(net "M_A_CPU0_SB_DQ<15>")
	)
	(segment
		(start 315.507878 -214.063326)
		(end 313.756548 -214.063326)
		(width 0.20066)
		(layer "F.Cu")
		(net "M_A_CPU0_SB_DQ<15>")
	)
	(segment
		(start 312.056018 -214.316564)
		(end 312.987182 -214.316564)
		(width 0.20066)
		(layer "F.Cu")
		(net "M_A_CPU0_SB_DQ<15>")
	)
	(segment
		(start 322.952618 -221.509082)
		(end 322.476114 -221.509082)
		(width 0.20066)
		(layer "F.Cu")
		(net "M_A_CPU0_SB_DQ<15>")
	)
	(segment
		(start 330.928218 -233.126026)
		(end 325.403464 -227.601272)
		(width 0.1016)
		(layer "F.Cu")
		(net "M_A_CPU0_SB_DQ<15>")
	)
	(segment
		(start 310.088026 -214.741506)
		(end 310.488584 -214.741506)
		(width 0.20066)
		(layer "F.Cu")
		(net "M_A_CPU0_SB_DQ<15>")
	)
	(segment
		(start 325.403464 -226.481894)
		(end 324.61073 -225.68916)
		(width 0.1016)
		(layer "F.Cu")
		(net "M_A_CPU0_SB_DQ<15>")
	)
	(segment
		(start 307.043074 -214.316564)
		(end 307.482748 -214.756238)
		(width 0.20066)
		(layer "F.Cu")
		(net "M_A_CPU0_SB_DQ<15>")
	)
	(segment
		(start 305.443382 -214.316564)
		(end 307.043074 -214.316564)
		(width 0.20066)
		(layer "F.Cu")
		(net "M_A_CPU0_SB_DQ<15>")
	)
	(segment
		(start 334.244442 -233.700066)
		(end 333.981552 -233.437176)
		(width 0.088646)
		(layer "F.Cu")
		(net "M_A_CPU0_SB_DQ<15>")
	)
	(segment
		(start 322.275454 -222.420942)
		(end 322.476114 -222.220282)
		(width 0.20066)
		(layer "F.Cu")
		(net "M_A_CPU0_SB_DQ<15>")
	)
	(segment
		(start 333.12354 -233.414824)
		(end 333.077312 -233.388662)
		(width 0.088646)
		(layer "F.Cu")
		(net "M_A_CPU0_SB_DQ<15>")
	)
	(segment
		(start 322.275454 -223.843342)
		(end 322.476114 -223.642682)
		(width 0.20066)
		(layer "F.Cu")
		(net "M_A_CPU0_SB_DQ<15>")
	)
	(segment
		(start 323.153278 -223.442022)
		(end 323.153278 -223.132142)
		(width 0.20066)
		(layer "F.Cu")
		(net "M_A_CPU0_SB_DQ<15>")
	)
	(segment
		(start 322.275454 -222.730822)
		(end 322.275454 -222.420942)
		(width 0.20066)
		(layer "F.Cu")
		(net "M_A_CPU0_SB_DQ<15>")
	)
	(segment
		(start 323.665596 -224.744026)
		(end 322.495926 -224.744026)
		(width 0.20066)
		(layer "F.Cu")
		(net "M_A_CPU0_SB_DQ<15>")
	)
	(segment
		(start 322.952618 -222.220282)
		(end 323.153278 -222.019622)
		(width 0.20066)
		(layer "F.Cu")
		(net "M_A_CPU0_SB_DQ<15>")
	)
	(segment
		(start 310.609996 -214.620094)
		(end 310.609996 -214.260684)
		(width 0.20066)
		(layer "F.Cu")
		(net "M_A_CPU0_SB_DQ<15>")
	)
	(segment
		(start 333.574644 -233.437176)
		(end 333.53629 -233.47553)
		(width 0.088646)
		(layer "F.Cu")
		(net "M_A_CPU0_SB_DQ<15>")
	)
	(segment
		(start 332.256638 -233.126026)
		(end 331.994764 -233.126026)
		(width 0.088646)
		(layer "F.Cu")
		(net "M_A_CPU0_SB_DQ<15>")
	)
	(segment
		(start 322.952618 -222.931482)
		(end 322.476114 -222.931482)
		(width 0.20066)
		(layer "F.Cu")
		(net "M_A_CPU0_SB_DQ<15>")
	)
	(segment
		(start 332.598014 -233.282744)
		(end 332.413356 -233.282744)
		(width 0.088646)
		(layer "F.Cu")
		(net "M_A_CPU0_SB_DQ<15>")
	)
	(segment
		(start 313.756548 -214.063326)
		(end 313.50331 -214.316564)
		(width 0.20066)
		(layer "F.Cu")
		(net "M_A_CPU0_SB_DQ<15>")
	)
	(segment
		(start 307.76291 -214.756238)
		(end 307.776626 -214.756238)
		(width 0.101854)
		(layer "F.Cu")
		(net "M_A_CPU0_SB_DQ<15>")
	)
	(segment
		(start 322.275454 -221.308422)
		(end 322.275454 -220.830902)
		(width 0.20066)
		(layer "F.Cu")
		(net "M_A_CPU0_SB_DQ<15>")
	)
	(segment
		(start 322.952618 -223.642682)
		(end 323.153278 -223.442022)
		(width 0.20066)
		(layer "F.Cu")
		(net "M_A_CPU0_SB_DQ<15>")
	)
	(segment
		(start 323.153278 -223.132142)
		(end 322.952618 -222.931482)
		(width 0.20066)
		(layer "F.Cu")
		(net "M_A_CPU0_SB_DQ<15>")
	)
	(segment
		(start 322.275454 -224.523554)
		(end 322.275454 -223.843342)
		(width 0.20066)
		(layer "F.Cu")
		(net "M_A_CPU0_SB_DQ<15>")
	)
	(segment
		(start 307.80228 -214.741506)
		(end 309.804054 -214.741506)
		(width 0.1016)
		(layer "F.Cu")
		(net "M_A_CPU0_SB_DQ<15>")
	)
	(segment
		(start 310.488584 -214.741506)
		(end 310.609996 -214.620094)
		(width 0.20066)
		(layer "F.Cu")
		(net "M_A_CPU0_SB_DQ<15>")
	)
	(segment
		(start 331.994764 -233.126026)
		(end 330.928218 -233.126026)
		(width 0.1016)
		(layer "F.Cu")
		(net "M_A_CPU0_SB_DQ<15>")
	)
	(segment
		(start 322.476114 -222.931482)
		(end 322.275454 -222.730822)
		(width 0.20066)
		(layer "F.Cu")
		(net "M_A_CPU0_SB_DQ<15>")
	)
	(segment
		(start 332.413356 -233.282744)
		(end 332.256638 -233.126026)
		(width 0.088646)
		(layer "F.Cu")
		(net "M_A_CPU0_SB_DQ<15>")
	)
	(segment
		(start 311.873138 -214.133684)
		(end 312.056018 -214.316564)
		(width 0.20066)
		(layer "F.Cu")
		(net "M_A_CPU0_SB_DQ<15>")
	)
	(segment
		(start 322.476114 -222.220282)
		(end 322.952618 -222.220282)
		(width 0.20066)
		(layer "F.Cu")
		(net "M_A_CPU0_SB_DQ<15>")
	)
	(segment
		(start 323.153278 -221.709742)
		(end 322.952618 -221.509082)
		(width 0.20066)
		(layer "F.Cu")
		(net "M_A_CPU0_SB_DQ<15>")
	)
	(segment
		(start 332.872588 -233.318304)
		(end 332.598014 -233.282744)
		(width 0.088646)
		(layer "F.Cu")
		(net "M_A_CPU0_SB_DQ<15>")
	)
	(segment
		(start 307.776626 -214.756238)
		(end 307.791358 -214.741506)
		(width 0.101854)
		(layer "F.Cu")
		(net "M_A_CPU0_SB_DQ<15>")
	)
	(segment
		(start 322.476114 -223.642682)
		(end 322.952618 -223.642682)
		(width 0.20066)
		(layer "F.Cu")
		(net "M_A_CPU0_SB_DQ<15>")
	)
	(arc
		(start 334.675734 -233.87812)
		(mid 334.44231 -233.832145)
		(end 334.244442 -233.700066)
		(width 0.088646)
		(layer "F.Cu")
		(net "M_A_CPU0_SB_DQ<15>")
	)
	(arc
		(start 333.45501 -233.501946)
		(mid 333.28363 -233.479847)
		(end 333.12354 -233.414824)
		(width 0.088646)
		(layer "F.Cu")
		(net "M_A_CPU0_SB_DQ<15>")
	)
	(arc
		(start 333.077312 -233.388662)
		(mid 332.978351 -233.343584)
		(end 332.872588 -233.318304)
		(width 0.088646)
		(layer "F.Cu")
		(net "M_A_CPU0_SB_DQ<15>")
	)
	(arc
		(start 333.981552 -233.437176)
		(mid 333.778098 -233.352903)
		(end 333.574644 -233.437176)
		(width 0.088646)
		(layer "F.Cu")
		(net "M_A_CPU0_SB_DQ<15>")
	)
	(arc
		(start 333.53629 -233.47553)
		(mid 333.507039 -233.495075)
		(end 333.472536 -233.501946)
		(width 0.088646)
		(layer "F.Cu")
		(net "M_A_CPU0_SB_DQ<15>")
	)
	(segment
		(start 323.27596 -226.258628)
		(end 323.082158 -226.064826)
		(width 0.20066)
		(layer "F.Cu")
		(net "M_A_CPU0_SB_DQ<14>")
	)
	(segment
		(start 322.57492 -226.064826)
		(end 322.37426 -226.265486)
		(width 0.20066)
		(layer "F.Cu")
		(net "M_A_CPU0_SB_DQ<14>")
	)
	(segment
		(start 307.77307 -216.441528)
		(end 308.028086 -216.441528)
		(width 0.101854)
		(layer "F.Cu")
		(net "M_A_CPU0_SB_DQ<14>")
	)
	(segment
		(start 324.27291 -227.166678)
		(end 324.04812 -226.941888)
		(width 0.20066)
		(layer "F.Cu")
		(net "M_A_CPU0_SB_DQ<14>")
	)
	(segment
		(start 321.86372 -227.192078)
		(end 321.66306 -226.991418)
		(width 0.20066)
		(layer "F.Cu")
		(net "M_A_CPU0_SB_DQ<14>")
	)
	(segment
		(start 323.50964 -226.941888)
		(end 323.27596 -226.708208)
		(width 0.20066)
		(layer "F.Cu")
		(net "M_A_CPU0_SB_DQ<14>")
	)
	(segment
		(start 323.27596 -226.708208)
		(end 323.27596 -226.258628)
		(width 0.20066)
		(layer "F.Cu")
		(net "M_A_CPU0_SB_DQ<14>")
	)
	(segment
		(start 314.507626 -215.406732)
		(end 313.897772 -216.016586)
		(width 0.20066)
		(layer "F.Cu")
		(net "M_A_CPU0_SB_DQ<14>")
	)
	(segment
		(start 307.467762 -216.451688)
		(end 307.76291 -216.451688)
		(width 0.20066)
		(layer "F.Cu")
		(net "M_A_CPU0_SB_DQ<14>")
	)
	(segment
		(start 331.461364 -234.170474)
		(end 331.110082 -234.170474)
		(width 0.1016)
		(layer "F.Cu")
		(net "M_A_CPU0_SB_DQ<14>")
	)
	(segment
		(start 310.58993 -216.338912)
		(end 310.58993 -215.99271)
		(width 0.20066)
		(layer "F.Cu")
		(net "M_A_CPU0_SB_DQ<14>")
	)
	(segment
		(start 315.01969 -215.406732)
		(end 314.507626 -215.406732)
		(width 0.20066)
		(layer "F.Cu")
		(net "M_A_CPU0_SB_DQ<14>")
	)
	(segment
		(start 321.4624 -226.064826)
		(end 321.215004 -226.064826)
		(width 0.20066)
		(layer "F.Cu")
		(net "M_A_CPU0_SB_DQ<14>")
	)
	(segment
		(start 321.66306 -226.265486)
		(end 321.4624 -226.064826)
		(width 0.20066)
		(layer "F.Cu")
		(net "M_A_CPU0_SB_DQ<14>")
	)
	(segment
		(start 332.16215 -234.533186)
		(end 331.799438 -234.170474)
		(width 0.088646)
		(layer "F.Cu")
		(net "M_A_CPU0_SB_DQ<14>")
	)
	(segment
		(start 331.110082 -234.170474)
		(end 324.629272 -227.689664)
		(width 0.1016)
		(layer "F.Cu")
		(net "M_A_CPU0_SB_DQ<14>")
	)
	(segment
		(start 320.95313 -221.340172)
		(end 315.01969 -215.406732)
		(width 0.20066)
		(layer "F.Cu")
		(net "M_A_CPU0_SB_DQ<14>")
	)
	(segment
		(start 320.95313 -225.802952)
		(end 320.95313 -221.340172)
		(width 0.20066)
		(layer "F.Cu")
		(net "M_A_CPU0_SB_DQ<14>")
	)
	(segment
		(start 335.142332 -234.689904)
		(end 334.440784 -234.285028)
		(width 0.088646)
		(layer "F.Cu")
		(net "M_A_CPU0_SB_DQ<14>")
	)
	(segment
		(start 310.58993 -215.99271)
		(end 310.767984 -215.814656)
		(width 0.20066)
		(layer "F.Cu")
		(net "M_A_CPU0_SB_DQ<14>")
	)
	(segment
		(start 322.37426 -226.991418)
		(end 322.1736 -227.192078)
		(width 0.20066)
		(layer "F.Cu")
		(net "M_A_CPU0_SB_DQ<14>")
	)
	(segment
		(start 324.629272 -227.52304)
		(end 324.27291 -227.166678)
		(width 0.1016)
		(layer "F.Cu")
		(net "M_A_CPU0_SB_DQ<14>")
	)
	(segment
		(start 305.443382 -216.016586)
		(end 307.03266 -216.016586)
		(width 0.20066)
		(layer "F.Cu")
		(net "M_A_CPU0_SB_DQ<14>")
	)
	(segment
		(start 310.487314 -216.441528)
		(end 310.58993 -216.338912)
		(width 0.20066)
		(layer "F.Cu")
		(net "M_A_CPU0_SB_DQ<14>")
	)
	(segment
		(start 322.1736 -227.192078)
		(end 321.86372 -227.192078)
		(width 0.20066)
		(layer "F.Cu")
		(net "M_A_CPU0_SB_DQ<14>")
	)
	(segment
		(start 308.028086 -216.441528)
		(end 309.815738 -216.441528)
		(width 0.1016)
		(layer "F.Cu")
		(net "M_A_CPU0_SB_DQ<14>")
	)
	(segment
		(start 309.815738 -216.441528)
		(end 310.088026 -216.441528)
		(width 0.101854)
		(layer "F.Cu")
		(net "M_A_CPU0_SB_DQ<14>")
	)
	(segment
		(start 324.629272 -227.689664)
		(end 324.629272 -227.52304)
		(width 0.1016)
		(layer "F.Cu")
		(net "M_A_CPU0_SB_DQ<14>")
	)
	(segment
		(start 311.083198 -215.814656)
		(end 311.285128 -216.016586)
		(width 0.20066)
		(layer "F.Cu")
		(net "M_A_CPU0_SB_DQ<14>")
	)
	(segment
		(start 323.082158 -226.064826)
		(end 322.57492 -226.064826)
		(width 0.20066)
		(layer "F.Cu")
		(net "M_A_CPU0_SB_DQ<14>")
	)
	(segment
		(start 333.044546 -234.277154)
		(end 332.788514 -234.533186)
		(width 0.088646)
		(layer "F.Cu")
		(net "M_A_CPU0_SB_DQ<14>")
	)
	(segment
		(start 322.37426 -226.265486)
		(end 322.37426 -226.991418)
		(width 0.20066)
		(layer "F.Cu")
		(net "M_A_CPU0_SB_DQ<14>")
	)
	(segment
		(start 321.215004 -226.064826)
		(end 320.95313 -225.802952)
		(width 0.20066)
		(layer "F.Cu")
		(net "M_A_CPU0_SB_DQ<14>")
	)
	(segment
		(start 311.285128 -216.016586)
		(end 312.987182 -216.016586)
		(width 0.20066)
		(layer "F.Cu")
		(net "M_A_CPU0_SB_DQ<14>")
	)
	(segment
		(start 307.76291 -216.451688)
		(end 307.77307 -216.441528)
		(width 0.101854)
		(layer "F.Cu")
		(net "M_A_CPU0_SB_DQ<14>")
	)
	(segment
		(start 313.897772 -216.016586)
		(end 312.987182 -216.016586)
		(width 0.20066)
		(layer "F.Cu")
		(net "M_A_CPU0_SB_DQ<14>")
	)
	(segment
		(start 307.03266 -216.016586)
		(end 307.467762 -216.451688)
		(width 0.20066)
		(layer "F.Cu")
		(net "M_A_CPU0_SB_DQ<14>")
	)
	(segment
		(start 310.767984 -215.814656)
		(end 311.083198 -215.814656)
		(width 0.20066)
		(layer "F.Cu")
		(net "M_A_CPU0_SB_DQ<14>")
	)
	(segment
		(start 332.788514 -234.533186)
		(end 332.16215 -234.533186)
		(width 0.088646)
		(layer "F.Cu")
		(net "M_A_CPU0_SB_DQ<14>")
	)
	(segment
		(start 324.04812 -226.941888)
		(end 323.50964 -226.941888)
		(width 0.20066)
		(layer "F.Cu")
		(net "M_A_CPU0_SB_DQ<14>")
	)
	(segment
		(start 321.66306 -226.991418)
		(end 321.66306 -226.265486)
		(width 0.20066)
		(layer "F.Cu")
		(net "M_A_CPU0_SB_DQ<14>")
	)
	(segment
		(start 310.088026 -216.441528)
		(end 310.487314 -216.441528)
		(width 0.20066)
		(layer "F.Cu")
		(net "M_A_CPU0_SB_DQ<14>")
	)
	(segment
		(start 331.799438 -234.170474)
		(end 331.461364 -234.170474)
		(width 0.088646)
		(layer "F.Cu")
		(net "M_A_CPU0_SB_DQ<14>")
	)
	(arc
		(start 334.440784 -234.285028)
		(mid 334.205834 -234.222102)
		(end 333.970884 -234.285028)
		(width 0.088646)
		(layer "F.Cu")
		(net "M_A_CPU0_SB_DQ<14>")
	)
	(arc
		(start 333.500984 -234.285028)
		(mid 333.273797 -234.222044)
		(end 333.044546 -234.277154)
		(width 0.088646)
		(layer "F.Cu")
		(net "M_A_CPU0_SB_DQ<14>")
	)
	(arc
		(start 335.14538 -234.69219)
		(mid 335.143929 -234.69095)
		(end 335.142332 -234.689904)
		(width 0.088646)
		(layer "F.Cu")
		(net "M_A_CPU0_SB_DQ<14>")
	)
	(arc
		(start 333.970884 -234.285028)
		(mid 333.735934 -234.347988)
		(end 333.500984 -234.285028)
		(width 0.088646)
		(layer "F.Cu")
		(net "M_A_CPU0_SB_DQ<14>")
	)
	(segment
		(start 311.91708 -214.73033)
		(end 311.203594 -214.73033)
		(width 0.20066)
		(layer "F.Cu")
		(net "M_A_CPU0_SB_DQ<13>")
	)
	(segment
		(start 302.730408 -215.417654)
		(end 303.271936 -215.417654)
		(width 0.20066)
		(layer "F.Cu")
		(net "M_A_CPU0_SB_DQ<13>")
	)
	(segment
		(start 333.735934 -233.87812)
		(end 333.186024 -233.671364)
		(width 0.088646)
		(layer "F.Cu")
		(net "M_A_CPU0_SB_DQ<13>")
	)
	(segment
		(start 303.271936 -215.417654)
		(end 303.54778 -215.14181)
		(width 0.20066)
		(layer "F.Cu")
		(net "M_A_CPU0_SB_DQ<13>")
	)
	(segment
		(start 325.098664 -227.727764)
		(end 324.954392 -227.583492)
		(width 0.101854)
		(layer "F.Cu")
		(net "M_A_CPU0_SB_DQ<13>")
	)
	(segment
		(start 303.54778 -214.896446)
		(end 303.71669 -214.727536)
		(width 0.20066)
		(layer "F.Cu")
		(net "M_A_CPU0_SB_DQ<13>")
	)
	(segment
		(start 315.267086 -214.73287)
		(end 314.12688 -214.73287)
		(width 0.20066)
		(layer "F.Cu")
		(net "M_A_CPU0_SB_DQ<13>")
	)
	(segment
		(start 304.319178 -214.727536)
		(end 304.333402 -214.74176)
		(width 0.1016)
		(layer "F.Cu")
		(net "M_A_CPU0_SB_DQ<13>")
	)
	(segment
		(start 302.479456 -215.166702)
		(end 302.730408 -215.417654)
		(width 0.20066)
		(layer "F.Cu")
		(net "M_A_CPU0_SB_DQ<13>")
	)
	(segment
		(start 333.186024 -233.671364)
		(end 332.982062 -233.553762)
		(width 0.088646)
		(layer "F.Cu")
		(net "M_A_CPU0_SB_DQ<13>")
	)
	(segment
		(start 314.087256 -214.741506)
		(end 312.12536 -214.741506)
		(width 0.1016)
		(layer "F.Cu")
		(net "M_A_CPU0_SB_DQ<13>")
	)
	(segment
		(start 312.12536 -214.741506)
		(end 311.945528 -214.741506)
		(width 0.101854)
		(layer "F.Cu")
		(net "M_A_CPU0_SB_DQ<13>")
	)
	(segment
		(start 307.208936 -215.166702)
		(end 308.887114 -215.166702)
		(width 0.20066)
		(layer "F.Cu")
		(net "M_A_CPU0_SB_DQ<13>")
	)
	(segment
		(start 301.343314 -215.166702)
		(end 302.479456 -215.166702)
		(width 0.20066)
		(layer "F.Cu")
		(net "M_A_CPU0_SB_DQ<13>")
	)
	(segment
		(start 324.380098 -226.36353)
		(end 323.413374 -225.396806)
		(width 0.20066)
		(layer "F.Cu")
		(net "M_A_CPU0_SB_DQ<13>")
	)
	(segment
		(start 306.783994 -214.74176)
		(end 307.208936 -215.166702)
		(width 0.20066)
		(layer "F.Cu")
		(net "M_A_CPU0_SB_DQ<13>")
	)
	(segment
		(start 311.934352 -214.73033)
		(end 311.91708 -214.73033)
		(width 0.101854)
		(layer "F.Cu")
		(net "M_A_CPU0_SB_DQ<13>")
	)
	(segment
		(start 321.635882 -221.101666)
		(end 315.267086 -214.73287)
		(width 0.20066)
		(layer "F.Cu")
		(net "M_A_CPU0_SB_DQ<13>")
	)
	(segment
		(start 311.203594 -214.73033)
		(end 310.767222 -215.166702)
		(width 0.20066)
		(layer "F.Cu")
		(net "M_A_CPU0_SB_DQ<13>")
	)
	(segment
		(start 324.380098 -226.364292)
		(end 324.380098 -226.36353)
		(width 0.20066)
		(layer "F.Cu")
		(net "M_A_CPU0_SB_DQ<13>")
	)
	(segment
		(start 330.903326 -233.532426)
		(end 325.098664 -227.727764)
		(width 0.1016)
		(layer "F.Cu")
		(net "M_A_CPU0_SB_DQ<13>")
	)
	(segment
		(start 306.313586 -214.74176)
		(end 306.644294 -214.74176)
		(width 0.101854)
		(layer "F.Cu")
		(net "M_A_CPU0_SB_DQ<13>")
	)
	(segment
		(start 314.12688 -214.73287)
		(end 314.095892 -214.73287)
		(width 0.101854)
		(layer "F.Cu")
		(net "M_A_CPU0_SB_DQ<13>")
	)
	(segment
		(start 332.643734 -233.489246)
		(end 332.128114 -233.489246)
		(width 0.088646)
		(layer "F.Cu")
		(net "M_A_CPU0_SB_DQ<13>")
	)
	(segment
		(start 314.095892 -214.73287)
		(end 314.087256 -214.741506)
		(width 0.101854)
		(layer "F.Cu")
		(net "M_A_CPU0_SB_DQ<13>")
	)
	(segment
		(start 303.71669 -214.727536)
		(end 304.319178 -214.727536)
		(width 0.20066)
		(layer "F.Cu")
		(net "M_A_CPU0_SB_DQ<13>")
	)
	(segment
		(start 331.893164 -233.532426)
		(end 330.903326 -233.532426)
		(width 0.1016)
		(layer "F.Cu")
		(net "M_A_CPU0_SB_DQ<13>")
	)
	(segment
		(start 311.945528 -214.741506)
		(end 311.934352 -214.73033)
		(width 0.101854)
		(layer "F.Cu")
		(net "M_A_CPU0_SB_DQ<13>")
	)
	(segment
		(start 324.954392 -226.938586)
		(end 324.380098 -226.364292)
		(width 0.1016)
		(layer "F.Cu")
		(net "M_A_CPU0_SB_DQ<13>")
	)
	(segment
		(start 331.959966 -233.532426)
		(end 331.893164 -233.532426)
		(width 0.088646)
		(layer "F.Cu")
		(net "M_A_CPU0_SB_DQ<13>")
	)
	(segment
		(start 321.635882 -224.85096)
		(end 321.635882 -221.101666)
		(width 0.20066)
		(layer "F.Cu")
		(net "M_A_CPU0_SB_DQ<13>")
	)
	(segment
		(start 303.54778 -215.14181)
		(end 303.54778 -214.896446)
		(width 0.20066)
		(layer "F.Cu")
		(net "M_A_CPU0_SB_DQ<13>")
	)
	(segment
		(start 306.644294 -214.74176)
		(end 306.783994 -214.74176)
		(width 0.20066)
		(layer "F.Cu")
		(net "M_A_CPU0_SB_DQ<13>")
	)
	(segment
		(start 322.181728 -225.396806)
		(end 321.635882 -224.85096)
		(width 0.20066)
		(layer "F.Cu")
		(net "M_A_CPU0_SB_DQ<13>")
	)
	(segment
		(start 332.794864 -233.50347)
		(end 332.643734 -233.489246)
		(width 0.088646)
		(layer "F.Cu")
		(net "M_A_CPU0_SB_DQ<13>")
	)
	(segment
		(start 332.128114 -233.489246)
		(end 331.959966 -233.532426)
		(width 0.088646)
		(layer "F.Cu")
		(net "M_A_CPU0_SB_DQ<13>")
	)
	(segment
		(start 304.333402 -214.74176)
		(end 306.313586 -214.74176)
		(width 0.1016)
		(layer "F.Cu")
		(net "M_A_CPU0_SB_DQ<13>")
	)
	(segment
		(start 310.767222 -215.166702)
		(end 308.887114 -215.166702)
		(width 0.20066)
		(layer "F.Cu")
		(net "M_A_CPU0_SB_DQ<13>")
	)
	(segment
		(start 324.954392 -227.583492)
		(end 324.954392 -226.938586)
		(width 0.1016)
		(layer "F.Cu")
		(net "M_A_CPU0_SB_DQ<13>")
	)
	(segment
		(start 323.413374 -225.396806)
		(end 322.181728 -225.396806)
		(width 0.20066)
		(layer "F.Cu")
		(net "M_A_CPU0_SB_DQ<13>")
	)
	(arc
		(start 332.982062 -233.553762)
		(mid 332.89177 -233.51631)
		(end 332.794864 -233.50347)
		(width 0.088646)
		(layer "F.Cu")
		(net "M_A_CPU0_SB_DQ<13>")
	)
	(segment
		(start 302.618648 -216.866724)
		(end 302.912018 -217.160094)
		(width 0.20066)
		(layer "F.Cu")
		(net "M_A_CPU0_SB_DQ<12>")
	)
	(segment
		(start 303.776634 -216.430098)
		(end 304.319178 -216.430098)
		(width 0.20066)
		(layer "F.Cu")
		(net "M_A_CPU0_SB_DQ<12>")
	)
	(segment
		(start 301.343314 -216.866724)
		(end 302.618648 -216.866724)
		(width 0.20066)
		(layer "F.Cu")
		(net "M_A_CPU0_SB_DQ<12>")
	)
	(segment
		(start 307.297074 -216.866724)
		(end 308.887114 -216.866724)
		(width 0.20066)
		(layer "F.Cu")
		(net "M_A_CPU0_SB_DQ<12>")
	)
	(segment
		(start 303.54778 -216.658952)
		(end 303.776634 -216.430098)
		(width 0.20066)
		(layer "F.Cu")
		(net "M_A_CPU0_SB_DQ<12>")
	)
	(segment
		(start 315.398912 -217.048334)
		(end 315.398912 -216.728802)
		(width 0.20066)
		(layer "F.Cu")
		(net "M_A_CPU0_SB_DQ<12>")
	)
	(segment
		(start 306.644294 -216.441782)
		(end 306.872132 -216.441782)
		(width 0.20066)
		(layer "F.Cu")
		(net "M_A_CPU0_SB_DQ<12>")
	)
	(segment
		(start 315.85408 -217.503502)
		(end 315.398912 -217.048334)
		(width 0.20066)
		(layer "F.Cu")
		(net "M_A_CPU0_SB_DQ<12>")
	)
	(segment
		(start 310.767222 -216.866724)
		(end 308.887114 -216.866724)
		(width 0.20066)
		(layer "F.Cu")
		(net "M_A_CPU0_SB_DQ<12>")
	)
	(segment
		(start 303.27219 -217.160094)
		(end 303.54778 -216.884504)
		(width 0.20066)
		(layer "F.Cu")
		(net "M_A_CPU0_SB_DQ<12>")
	)
	(segment
		(start 304.319178 -216.430098)
		(end 304.327306 -216.430098)
		(width 0.101854)
		(layer "F.Cu")
		(net "M_A_CPU0_SB_DQ<12>")
	)
	(segment
		(start 330.983336 -234.475274)
		(end 324.553834 -228.045772)
		(width 0.1016)
		(layer "F.Cu")
		(net "M_A_CPU0_SB_DQ<12>")
	)
	(segment
		(start 304.33899 -216.441782)
		(end 306.313586 -216.441782)
		(width 0.1016)
		(layer "F.Cu")
		(net "M_A_CPU0_SB_DQ<12>")
	)
	(segment
		(start 304.327306 -216.430098)
		(end 304.33899 -216.441782)
		(width 0.1016)
		(layer "F.Cu")
		(net "M_A_CPU0_SB_DQ<12>")
	)
	(segment
		(start 311.91708 -216.43213)
		(end 311.201816 -216.43213)
		(width 0.20066)
		(layer "F.Cu")
		(net "M_A_CPU0_SB_DQ<12>")
	)
	(segment
		(start 331.805788 -234.475274)
		(end 331.461364 -234.475274)
		(width 0.088646)
		(layer "F.Cu")
		(net "M_A_CPU0_SB_DQ<12>")
	)
	(segment
		(start 311.201816 -216.43213)
		(end 310.767222 -216.866724)
		(width 0.20066)
		(layer "F.Cu")
		(net "M_A_CPU0_SB_DQ<12>")
	)
	(segment
		(start 324.27291 -227.842572)
		(end 321.386962 -227.842572)
		(width 0.20066)
		(layer "F.Cu")
		(net "M_A_CPU0_SB_DQ<12>")
	)
	(segment
		(start 314.117736 -216.441528)
		(end 312.12536 -216.441528)
		(width 0.1016)
		(layer "F.Cu")
		(net "M_A_CPU0_SB_DQ<12>")
	)
	(segment
		(start 320.291968 -226.747578)
		(end 320.291968 -221.621858)
		(width 0.20066)
		(layer "F.Cu")
		(net "M_A_CPU0_SB_DQ<12>")
	)
	(segment
		(start 302.912018 -217.160094)
		(end 303.27219 -217.160094)
		(width 0.20066)
		(layer "F.Cu")
		(net "M_A_CPU0_SB_DQ<12>")
	)
	(segment
		(start 332.056994 -234.72648)
		(end 331.805788 -234.475274)
		(width 0.088646)
		(layer "F.Cu")
		(net "M_A_CPU0_SB_DQ<12>")
	)
	(segment
		(start 324.293738 -227.842572)
		(end 324.27291 -227.842572)
		(width 0.1016)
		(layer "F.Cu")
		(net "M_A_CPU0_SB_DQ<12>")
	)
	(segment
		(start 321.386962 -227.842572)
		(end 320.291968 -226.747578)
		(width 0.20066)
		(layer "F.Cu")
		(net "M_A_CPU0_SB_DQ<12>")
	)
	(segment
		(start 316.173612 -217.503502)
		(end 315.85408 -217.503502)
		(width 0.20066)
		(layer "F.Cu")
		(net "M_A_CPU0_SB_DQ<12>")
	)
	(segment
		(start 314.12688 -216.432384)
		(end 314.117736 -216.441528)
		(width 0.101854)
		(layer "F.Cu")
		(net "M_A_CPU0_SB_DQ<12>")
	)
	(segment
		(start 324.553834 -228.045772)
		(end 324.496938 -228.045772)
		(width 0.1016)
		(layer "F.Cu")
		(net "M_A_CPU0_SB_DQ<12>")
	)
	(segment
		(start 306.313586 -216.441782)
		(end 306.644294 -216.441782)
		(width 0.101854)
		(layer "F.Cu")
		(net "M_A_CPU0_SB_DQ<12>")
	)
	(segment
		(start 324.496938 -228.045772)
		(end 324.293738 -227.842572)
		(width 0.1016)
		(layer "F.Cu")
		(net "M_A_CPU0_SB_DQ<12>")
	)
	(segment
		(start 320.291968 -221.621858)
		(end 316.173612 -217.503502)
		(width 0.20066)
		(layer "F.Cu")
		(net "M_A_CPU0_SB_DQ<12>")
	)
	(segment
		(start 331.461364 -234.475274)
		(end 330.983336 -234.475274)
		(width 0.1016)
		(layer "F.Cu")
		(net "M_A_CPU0_SB_DQ<12>")
	)
	(segment
		(start 312.12536 -216.441528)
		(end 311.928764 -216.441528)
		(width 0.101854)
		(layer "F.Cu")
		(net "M_A_CPU0_SB_DQ<12>")
	)
	(segment
		(start 315.398912 -216.728802)
		(end 315.102494 -216.432384)
		(width 0.20066)
		(layer "F.Cu")
		(net "M_A_CPU0_SB_DQ<12>")
	)
	(segment
		(start 333.23149 -234.72648)
		(end 332.056994 -234.72648)
		(width 0.088646)
		(layer "F.Cu")
		(net "M_A_CPU0_SB_DQ<12>")
	)
	(segment
		(start 303.54778 -216.884504)
		(end 303.54778 -216.658952)
		(width 0.20066)
		(layer "F.Cu")
		(net "M_A_CPU0_SB_DQ<12>")
	)
	(segment
		(start 306.872132 -216.441782)
		(end 307.297074 -216.866724)
		(width 0.20066)
		(layer "F.Cu")
		(net "M_A_CPU0_SB_DQ<12>")
	)
	(segment
		(start 333.26578 -234.69219)
		(end 333.23149 -234.72648)
		(width 0.088646)
		(layer "F.Cu")
		(net "M_A_CPU0_SB_DQ<12>")
	)
	(segment
		(start 315.102494 -216.432384)
		(end 314.12688 -216.432384)
		(width 0.20066)
		(layer "F.Cu")
		(net "M_A_CPU0_SB_DQ<12>")
	)
	(segment
		(start 311.928764 -216.441528)
		(end 311.919366 -216.43213)
		(width 0.101854)
		(layer "F.Cu")
		(net "M_A_CPU0_SB_DQ<12>")
	)
	(segment
		(start 311.919366 -216.43213)
		(end 311.91708 -216.43213)
		(width 0.101854)
		(layer "F.Cu")
		(net "M_A_CPU0_SB_DQ<12>")
	)
	(segment
		(start 313.793124 -220.266768)
		(end 312.987182 -220.266768)
		(width 0.20066)
		(layer "F.Cu")
		(net "M_A_CPU0_SB_DQ<11>")
	)
	(segment
		(start 317.387732 -226.08413)
		(end 317.187072 -225.88347)
		(width 0.20066)
		(layer "F.Cu")
		(net "M_A_CPU0_SB_DQ<11>")
	)
	(segment
		(start 317.387732 -228.005132)
		(end 317.387732 -227.50653)
		(width 0.20066)
		(layer "F.Cu")
		(net "M_A_CPU0_SB_DQ<11>")
	)
	(segment
		(start 305.443382 -220.266768)
		(end 306.872386 -220.266768)
		(width 0.20066)
		(layer "F.Cu")
		(net "M_A_CPU0_SB_DQ<11>")
	)
	(segment
		(start 310.646826 -220.564964)
		(end 310.646826 -220.3704)
		(width 0.20066)
		(layer "F.Cu")
		(net "M_A_CPU0_SB_DQ<11>")
	)
	(segment
		(start 310.49468 -220.71711)
		(end 310.646826 -220.564964)
		(width 0.20066)
		(layer "F.Cu")
		(net "M_A_CPU0_SB_DQ<11>")
	)
	(segment
		(start 317.387732 -224.66173)
		(end 317.187072 -224.46107)
		(width 0.20066)
		(layer "F.Cu")
		(net "M_A_CPU0_SB_DQ<11>")
	)
	(segment
		(start 333.462884 -235.913422)
		(end 333.45882 -235.917486)
		(width 0.088646)
		(layer "F.Cu")
		(net "M_A_CPU0_SB_DQ<11>")
	)
	(segment
		(start 330.421488 -236.069886)
		(end 325.182738 -230.831136)
		(width 0.1016)
		(layer "F.Cu")
		(net "M_A_CPU0_SB_DQ<11>")
	)
	(segment
		(start 311.877456 -220.405452)
		(end 312.01614 -220.266768)
		(width 0.20066)
		(layer "F.Cu")
		(net "M_A_CPU0_SB_DQ<11>")
	)
	(segment
		(start 324.27291 -230.831136)
		(end 320.213736 -230.831136)
		(width 0.20066)
		(layer "F.Cu")
		(net "M_A_CPU0_SB_DQ<11>")
	)
	(segment
		(start 317.387732 -222.776034)
		(end 315.12891 -220.517212)
		(width 0.20066)
		(layer "F.Cu")
		(net "M_A_CPU0_SB_DQ<11>")
	)
	(segment
		(start 316.840616 -224.46107)
		(end 316.639956 -224.26041)
		(width 0.20066)
		(layer "F.Cu")
		(net "M_A_CPU0_SB_DQ<11>")
	)
	(segment
		(start 334.251046 -235.913422)
		(end 333.462884 -235.913422)
		(width 0.088646)
		(layer "F.Cu")
		(net "M_A_CPU0_SB_DQ<11>")
	)
	(segment
		(start 317.187072 -227.30587)
		(end 316.840616 -227.30587)
		(width 0.20066)
		(layer "F.Cu")
		(net "M_A_CPU0_SB_DQ<11>")
	)
	(segment
		(start 309.804054 -220.69171)
		(end 309.829454 -220.71711)
		(width 0.1016)
		(layer "F.Cu")
		(net "M_A_CPU0_SB_DQ<11>")
	)
	(segment
		(start 317.387732 -224.97161)
		(end 317.387732 -224.66173)
		(width 0.20066)
		(layer "F.Cu")
		(net "M_A_CPU0_SB_DQ<11>")
	)
	(segment
		(start 312.01614 -220.266768)
		(end 312.987182 -220.266768)
		(width 0.20066)
		(layer "F.Cu")
		(net "M_A_CPU0_SB_DQ<11>")
	)
	(segment
		(start 308.036722 -220.69171)
		(end 309.804054 -220.69171)
		(width 0.1016)
		(layer "F.Cu")
		(net "M_A_CPU0_SB_DQ<11>")
	)
	(segment
		(start 306.872386 -220.266768)
		(end 307.382672 -220.777054)
		(width 0.20066)
		(layer "F.Cu")
		(net "M_A_CPU0_SB_DQ<11>")
	)
	(segment
		(start 317.187072 -226.59467)
		(end 317.387732 -226.39401)
		(width 0.20066)
		(layer "F.Cu")
		(net "M_A_CPU0_SB_DQ<11>")
	)
	(segment
		(start 311.179464 -220.172534)
		(end 311.412382 -220.405452)
		(width 0.20066)
		(layer "F.Cu")
		(net "M_A_CPU0_SB_DQ<11>")
	)
	(segment
		(start 311.412382 -220.405452)
		(end 311.877456 -220.405452)
		(width 0.20066)
		(layer "F.Cu")
		(net "M_A_CPU0_SB_DQ<11>")
	)
	(segment
		(start 317.187072 -225.17227)
		(end 317.387732 -224.97161)
		(width 0.20066)
		(layer "F.Cu")
		(net "M_A_CPU0_SB_DQ<11>")
	)
	(segment
		(start 331.461364 -236.069886)
		(end 330.421488 -236.069886)
		(width 0.1016)
		(layer "F.Cu")
		(net "M_A_CPU0_SB_DQ<11>")
	)
	(segment
		(start 307.951378 -220.777054)
		(end 308.036722 -220.69171)
		(width 0.1016)
		(layer "F.Cu")
		(net "M_A_CPU0_SB_DQ<11>")
	)
	(segment
		(start 316.639956 -225.37293)
		(end 316.840616 -225.17227)
		(width 0.20066)
		(layer "F.Cu")
		(net "M_A_CPU0_SB_DQ<11>")
	)
	(segment
		(start 335.1403 -235.88853)
		(end 334.95869 -235.994956)
		(width 0.088646)
		(layer "F.Cu")
		(net "M_A_CPU0_SB_DQ<11>")
	)
	(segment
		(start 316.639956 -223.95053)
		(end 316.840616 -223.74987)
		(width 0.20066)
		(layer "F.Cu")
		(net "M_A_CPU0_SB_DQ<11>")
	)
	(segment
		(start 316.639956 -225.68281)
		(end 316.639956 -225.37293)
		(width 0.20066)
		(layer "F.Cu")
		(net "M_A_CPU0_SB_DQ<11>")
	)
	(segment
		(start 316.840616 -223.74987)
		(end 317.187072 -223.74987)
		(width 0.20066)
		(layer "F.Cu")
		(net "M_A_CPU0_SB_DQ<11>")
	)
	(segment
		(start 317.387732 -223.54921)
		(end 317.387732 -222.776034)
		(width 0.20066)
		(layer "F.Cu")
		(net "M_A_CPU0_SB_DQ<11>")
	)
	(segment
		(start 316.840616 -225.17227)
		(end 317.187072 -225.17227)
		(width 0.20066)
		(layer "F.Cu")
		(net "M_A_CPU0_SB_DQ<11>")
	)
	(segment
		(start 317.387732 -227.50653)
		(end 317.187072 -227.30587)
		(width 0.20066)
		(layer "F.Cu")
		(net "M_A_CPU0_SB_DQ<11>")
	)
	(segment
		(start 310.088026 -220.71711)
		(end 310.49468 -220.71711)
		(width 0.20066)
		(layer "F.Cu")
		(net "M_A_CPU0_SB_DQ<11>")
	)
	(segment
		(start 316.840616 -225.88347)
		(end 316.639956 -225.68281)
		(width 0.20066)
		(layer "F.Cu")
		(net "M_A_CPU0_SB_DQ<11>")
	)
	(segment
		(start 309.829454 -220.71711)
		(end 310.088026 -220.71711)
		(width 0.101854)
		(layer "F.Cu")
		(net "M_A_CPU0_SB_DQ<11>")
	)
	(segment
		(start 316.639956 -227.10521)
		(end 316.639956 -226.79533)
		(width 0.20066)
		(layer "F.Cu")
		(net "M_A_CPU0_SB_DQ<11>")
	)
	(segment
		(start 334.948276 -236.001052)
		(end 334.94726 -236.001814)
		(width 0.088646)
		(layer "F.Cu")
		(net "M_A_CPU0_SB_DQ<11>")
	)
	(segment
		(start 334.393032 -235.995464)
		(end 334.251046 -235.913422)
		(width 0.088646)
		(layer "F.Cu")
		(net "M_A_CPU0_SB_DQ<11>")
	)
	(segment
		(start 335.14538 -236.319822)
		(end 335.300574 -236.050836)
		(width 0.088646)
		(layer "F.Cu")
		(net "M_A_CPU0_SB_DQ<11>")
	)
	(segment
		(start 332.878176 -236.069886)
		(end 331.461364 -236.069886)
		(width 0.088646)
		(layer "F.Cu")
		(net "M_A_CPU0_SB_DQ<11>")
	)
	(segment
		(start 325.182738 -230.831136)
		(end 324.27291 -230.831136)
		(width 0.1016)
		(layer "F.Cu")
		(net "M_A_CPU0_SB_DQ<11>")
	)
	(segment
		(start 317.187072 -225.88347)
		(end 316.840616 -225.88347)
		(width 0.20066)
		(layer "F.Cu")
		(net "M_A_CPU0_SB_DQ<11>")
	)
	(segment
		(start 333.45882 -235.917486)
		(end 333.324454 -235.917486)
		(width 0.088646)
		(layer "F.Cu")
		(net "M_A_CPU0_SB_DQ<11>")
	)
	(segment
		(start 314.043568 -220.517212)
		(end 313.793124 -220.266768)
		(width 0.20066)
		(layer "F.Cu")
		(net "M_A_CPU0_SB_DQ<11>")
	)
	(segment
		(start 316.639956 -224.26041)
		(end 316.639956 -223.95053)
		(width 0.20066)
		(layer "F.Cu")
		(net "M_A_CPU0_SB_DQ<11>")
	)
	(segment
		(start 317.187072 -224.46107)
		(end 316.840616 -224.46107)
		(width 0.20066)
		(layer "F.Cu")
		(net "M_A_CPU0_SB_DQ<11>")
	)
	(segment
		(start 317.387732 -226.39401)
		(end 317.387732 -226.08413)
		(width 0.20066)
		(layer "F.Cu")
		(net "M_A_CPU0_SB_DQ<11>")
	)
	(segment
		(start 307.76291 -220.777054)
		(end 307.82768 -220.777054)
		(width 0.101854)
		(layer "F.Cu")
		(net "M_A_CPU0_SB_DQ<11>")
	)
	(segment
		(start 317.187072 -223.74987)
		(end 317.387732 -223.54921)
		(width 0.20066)
		(layer "F.Cu")
		(net "M_A_CPU0_SB_DQ<11>")
	)
	(segment
		(start 310.646826 -220.3704)
		(end 310.844692 -220.172534)
		(width 0.20066)
		(layer "F.Cu")
		(net "M_A_CPU0_SB_DQ<11>")
	)
	(segment
		(start 315.12891 -220.517212)
		(end 314.043568 -220.517212)
		(width 0.20066)
		(layer "F.Cu")
		(net "M_A_CPU0_SB_DQ<11>")
	)
	(segment
		(start 316.840616 -227.30587)
		(end 316.639956 -227.10521)
		(width 0.20066)
		(layer "F.Cu")
		(net "M_A_CPU0_SB_DQ<11>")
	)
	(segment
		(start 333.114904 -235.973874)
		(end 333.077312 -235.995464)
		(width 0.088646)
		(layer "F.Cu")
		(net "M_A_CPU0_SB_DQ<11>")
	)
	(segment
		(start 335.300574 -236.050836)
		(end 335.27111 -235.942124)
		(width 0.088646)
		(layer "F.Cu")
		(net "M_A_CPU0_SB_DQ<11>")
	)
	(segment
		(start 307.82768 -220.777054)
		(end 307.951378 -220.777054)
		(width 0.1016)
		(layer "F.Cu")
		(net "M_A_CPU0_SB_DQ<11>")
	)
	(segment
		(start 310.844692 -220.172534)
		(end 311.179464 -220.172534)
		(width 0.20066)
		(layer "F.Cu")
		(net "M_A_CPU0_SB_DQ<11>")
	)
	(segment
		(start 316.840616 -226.59467)
		(end 317.187072 -226.59467)
		(width 0.20066)
		(layer "F.Cu")
		(net "M_A_CPU0_SB_DQ<11>")
	)
	(segment
		(start 307.382672 -220.777054)
		(end 307.76291 -220.777054)
		(width 0.20066)
		(layer "F.Cu")
		(net "M_A_CPU0_SB_DQ<11>")
	)
	(segment
		(start 316.639956 -226.79533)
		(end 316.840616 -226.59467)
		(width 0.20066)
		(layer "F.Cu")
		(net "M_A_CPU0_SB_DQ<11>")
	)
	(segment
		(start 320.213736 -230.831136)
		(end 317.387732 -228.005132)
		(width 0.20066)
		(layer "F.Cu")
		(net "M_A_CPU0_SB_DQ<11>")
	)
	(arc
		(start 334.95869 -235.994956)
		(mid 334.957167 -235.995847)
		(end 334.955642 -235.996734)
		(width 0.088646)
		(layer "F.Cu")
		(net "M_A_CPU0_SB_DQ<11>")
	)
	(arc
		(start 334.955642 -235.996734)
		(mid 334.955007 -235.997114)
		(end 334.954372 -235.997496)
		(width 0.088646)
		(layer "F.Cu")
		(net "M_A_CPU0_SB_DQ<11>")
	)
	(arc
		(start 333.324454 -235.917486)
		(mid 333.215959 -235.931859)
		(end 333.114904 -235.973874)
		(width 0.088646)
		(layer "F.Cu")
		(net "M_A_CPU0_SB_DQ<11>")
	)
	(arc
		(start 335.27111 -235.942124)
		(mid 335.218964 -235.882966)
		(end 335.1403 -235.88853)
		(width 0.088646)
		(layer "F.Cu")
		(net "M_A_CPU0_SB_DQ<11>")
	)
	(arc
		(start 332.902814 -236.0676)
		(mid 332.890549 -236.069323)
		(end 332.878176 -236.069886)
		(width 0.088646)
		(layer "F.Cu")
		(net "M_A_CPU0_SB_DQ<11>")
	)
	(arc
		(start 332.938628 -236.058202)
		(mid 332.920878 -236.063497)
		(end 332.902814 -236.0676)
		(width 0.088646)
		(layer "F.Cu")
		(net "M_A_CPU0_SB_DQ<11>")
	)
	(arc
		(start 334.954372 -235.997496)
		(mid 334.95133 -235.999284)
		(end 334.948276 -236.001052)
		(width 0.088646)
		(layer "F.Cu")
		(net "M_A_CPU0_SB_DQ<11>")
	)
	(arc
		(start 333.077312 -235.995464)
		(mid 333.009533 -236.030287)
		(end 332.938628 -236.058202)
		(width 0.088646)
		(layer "F.Cu")
		(net "M_A_CPU0_SB_DQ<11>")
	)
	(arc
		(start 334.94726 -236.001814)
		(mid 334.669307 -236.071259)
		(end 334.393032 -235.995464)
		(width 0.088646)
		(layer "F.Cu")
		(net "M_A_CPU0_SB_DQ<11>")
	)
	(segment
		(start 325.622158 -232.13314)
		(end 325.188072 -232.13314)
		(width 0.1016)
		(layer "F.Cu")
		(net "M_A_CPU0_SB_DQ<10>")
	)
	(segment
		(start 318.442086 -231.337358)
		(end 318.442086 -231.053386)
		(width 0.20066)
		(layer "F.Cu")
		(net "M_A_CPU0_SB_DQ<10>")
	)
	(segment
		(start 331.742288 -236.679486)
		(end 331.461364 -236.679486)
		(width 0.088646)
		(layer "F.Cu")
		(net "M_A_CPU0_SB_DQ<10>")
	)
	(segment
		(start 316.190884 -230.287068)
		(end 315.299598 -229.395782)
		(width 0.20066)
		(layer "F.Cu")
		(net "M_A_CPU0_SB_DQ<10>")
	)
	(segment
		(start 332.62824 -236.529626)
		(end 331.892148 -236.529626)
		(width 0.088646)
		(layer "F.Cu")
		(net "M_A_CPU0_SB_DQ<10>")
	)
	(segment
		(start 317.436246 -230.331518)
		(end 317.436246 -230.047546)
		(width 0.20066)
		(layer "F.Cu")
		(net "M_A_CPU0_SB_DQ<10>")
	)
	(segment
		(start 309.804308 -222.391732)
		(end 310.070246 -222.391732)
		(width 0.101854)
		(layer "F.Cu")
		(net "M_A_CPU0_SB_DQ<10>")
	)
	(segment
		(start 316.977776 -230.789988)
		(end 317.436246 -230.331518)
		(width 0.20066)
		(layer "F.Cu")
		(net "M_A_CPU0_SB_DQ<10>")
	)
	(segment
		(start 318.363092 -232.459276)
		(end 317.983616 -232.0798)
		(width 0.20066)
		(layer "F.Cu")
		(net "M_A_CPU0_SB_DQ<10>")
	)
	(segment
		(start 318.442086 -231.053386)
		(end 318.223138 -230.834438)
		(width 0.20066)
		(layer "F.Cu")
		(net "M_A_CPU0_SB_DQ<10>")
	)
	(segment
		(start 307.961538 -222.479108)
		(end 308.038754 -222.401892)
		(width 0.101854)
		(layer "F.Cu")
		(net "M_A_CPU0_SB_DQ<10>")
	)
	(segment
		(start 307.022246 -221.96679)
		(end 307.534564 -222.479108)
		(width 0.20066)
		(layer "F.Cu")
		(net "M_A_CPU0_SB_DQ<10>")
	)
	(segment
		(start 310.53024 -221.990666)
		(end 310.736996 -221.78391)
		(width 0.20066)
		(layer "F.Cu")
		(net "M_A_CPU0_SB_DQ<10>")
	)
	(segment
		(start 317.436246 -230.047546)
		(end 317.217298 -229.828598)
		(width 0.20066)
		(layer "F.Cu")
		(net "M_A_CPU0_SB_DQ<10>")
	)
	(segment
		(start 314.768484 -221.96679)
		(end 312.987182 -221.96679)
		(width 0.20066)
		(layer "F.Cu")
		(net "M_A_CPU0_SB_DQ<10>")
	)
	(segment
		(start 311.20461 -221.96679)
		(end 312.987182 -221.96679)
		(width 0.20066)
		(layer "F.Cu")
		(net "M_A_CPU0_SB_DQ<10>")
	)
	(segment
		(start 316.977776 -231.07396)
		(end 316.977776 -230.789988)
		(width 0.20066)
		(layer "F.Cu")
		(net "M_A_CPU0_SB_DQ<10>")
	)
	(segment
		(start 310.357774 -222.409512)
		(end 310.53024 -222.237046)
		(width 0.20066)
		(layer "F.Cu")
		(net "M_A_CPU0_SB_DQ<10>")
	)
	(segment
		(start 317.983616 -231.795828)
		(end 318.442086 -231.337358)
		(width 0.20066)
		(layer "F.Cu")
		(net "M_A_CPU0_SB_DQ<10>")
	)
	(segment
		(start 317.983616 -232.0798)
		(end 317.983616 -231.795828)
		(width 0.20066)
		(layer "F.Cu")
		(net "M_A_CPU0_SB_DQ<10>")
	)
	(segment
		(start 331.892148 -236.529626)
		(end 331.742288 -236.679486)
		(width 0.088646)
		(layer "F.Cu")
		(net "M_A_CPU0_SB_DQ<10>")
	)
	(segment
		(start 330.168504 -236.679486)
		(end 325.622158 -232.13314)
		(width 0.1016)
		(layer "F.Cu")
		(net "M_A_CPU0_SB_DQ<10>")
	)
	(segment
		(start 317.196724 -231.292908)
		(end 316.977776 -231.07396)
		(width 0.20066)
		(layer "F.Cu")
		(net "M_A_CPU0_SB_DQ<10>")
	)
	(segment
		(start 334.675734 -237.133892)
		(end 333.970884 -236.726984)
		(width 0.088646)
		(layer "F.Cu")
		(net "M_A_CPU0_SB_DQ<10>")
	)
	(segment
		(start 305.443382 -221.96679)
		(end 307.022246 -221.96679)
		(width 0.20066)
		(layer "F.Cu")
		(net "M_A_CPU0_SB_DQ<10>")
	)
	(segment
		(start 325.045832 -232.13314)
		(end 324.719696 -232.459276)
		(width 0.20066)
		(layer "F.Cu")
		(net "M_A_CPU0_SB_DQ<10>")
	)
	(segment
		(start 317.217298 -229.828598)
		(end 316.933326 -229.828598)
		(width 0.20066)
		(layer "F.Cu")
		(net "M_A_CPU0_SB_DQ<10>")
	)
	(segment
		(start 325.188072 -232.13314)
		(end 325.045832 -232.13314)
		(width 0.20066)
		(layer "F.Cu")
		(net "M_A_CPU0_SB_DQ<10>")
	)
	(segment
		(start 310.088026 -222.409512)
		(end 310.357774 -222.409512)
		(width 0.20066)
		(layer "F.Cu")
		(net "M_A_CPU0_SB_DQ<10>")
	)
	(segment
		(start 316.933326 -229.828598)
		(end 316.474856 -230.287068)
		(width 0.20066)
		(layer "F.Cu")
		(net "M_A_CPU0_SB_DQ<10>")
	)
	(segment
		(start 307.76291 -222.479108)
		(end 307.961538 -222.479108)
		(width 0.101854)
		(layer "F.Cu")
		(net "M_A_CPU0_SB_DQ<10>")
	)
	(segment
		(start 315.299598 -222.497904)
		(end 314.768484 -221.96679)
		(width 0.20066)
		(layer "F.Cu")
		(net "M_A_CPU0_SB_DQ<10>")
	)
	(segment
		(start 317.480696 -231.292908)
		(end 317.196724 -231.292908)
		(width 0.20066)
		(layer "F.Cu")
		(net "M_A_CPU0_SB_DQ<10>")
	)
	(segment
		(start 317.939166 -230.834438)
		(end 317.480696 -231.292908)
		(width 0.20066)
		(layer "F.Cu")
		(net "M_A_CPU0_SB_DQ<10>")
	)
	(segment
		(start 316.474856 -230.287068)
		(end 316.190884 -230.287068)
		(width 0.20066)
		(layer "F.Cu")
		(net "M_A_CPU0_SB_DQ<10>")
	)
	(segment
		(start 311.02173 -221.78391)
		(end 311.20461 -221.96679)
		(width 0.20066)
		(layer "F.Cu")
		(net "M_A_CPU0_SB_DQ<10>")
	)
	(segment
		(start 324.719696 -232.459276)
		(end 318.363092 -232.459276)
		(width 0.20066)
		(layer "F.Cu")
		(net "M_A_CPU0_SB_DQ<10>")
	)
	(segment
		(start 331.461364 -236.679486)
		(end 330.168504 -236.679486)
		(width 0.1016)
		(layer "F.Cu")
		(net "M_A_CPU0_SB_DQ<10>")
	)
	(segment
		(start 308.07279 -222.391732)
		(end 309.804308 -222.391732)
		(width 0.1016)
		(layer "F.Cu")
		(net "M_A_CPU0_SB_DQ<10>")
	)
	(segment
		(start 310.53024 -222.237046)
		(end 310.53024 -221.990666)
		(width 0.20066)
		(layer "F.Cu")
		(net "M_A_CPU0_SB_DQ<10>")
	)
	(segment
		(start 310.070246 -222.391732)
		(end 310.088026 -222.409512)
		(width 0.101854)
		(layer "F.Cu")
		(net "M_A_CPU0_SB_DQ<10>")
	)
	(segment
		(start 308.038754 -222.401892)
		(end 308.07279 -222.391732)
		(width 0.1016)
		(layer "F.Cu")
		(net "M_A_CPU0_SB_DQ<10>")
	)
	(segment
		(start 307.534564 -222.479108)
		(end 307.76291 -222.479108)
		(width 0.20066)
		(layer "F.Cu")
		(net "M_A_CPU0_SB_DQ<10>")
	)
	(segment
		(start 310.736996 -221.78391)
		(end 311.02173 -221.78391)
		(width 0.20066)
		(layer "F.Cu")
		(net "M_A_CPU0_SB_DQ<10>")
	)
	(segment
		(start 318.223138 -230.834438)
		(end 317.939166 -230.834438)
		(width 0.20066)
		(layer "F.Cu")
		(net "M_A_CPU0_SB_DQ<10>")
	)
	(segment
		(start 315.299598 -229.395782)
		(end 315.299598 -222.497904)
		(width 0.20066)
		(layer "F.Cu")
		(net "M_A_CPU0_SB_DQ<10>")
	)
	(segment
		(start 333.500984 -236.726984)
		(end 333.36484 -236.726984)
		(width 0.088646)
		(layer "F.Cu")
		(net "M_A_CPU0_SB_DQ<10>")
	)
	(arc
		(start 333.067152 -236.647228)
		(mid 332.855433 -236.559559)
		(end 332.62824 -236.529626)
		(width 0.088646)
		(layer "F.Cu")
		(net "M_A_CPU0_SB_DQ<10>")
	)
	(arc
		(start 333.36484 -236.726984)
		(mid 333.210743 -236.706705)
		(end 333.067152 -236.647228)
		(width 0.088646)
		(layer "F.Cu")
		(net "M_A_CPU0_SB_DQ<10>")
	)
	(arc
		(start 333.970884 -236.726984)
		(mid 333.735934 -236.664024)
		(end 333.500984 -236.726984)
		(width 0.088646)
		(layer "F.Cu")
		(net "M_A_CPU0_SB_DQ<10>")
	)
	(segment
		(start 303.71923 -231.700324)
		(end 303.523396 -231.896158)
		(width 0.20066)
		(layer "F.Cu")
		(net "M_A_CPU0_SB_DQ<0>")
	)
	(segment
		(start 304.550826 -231.741726)
		(end 304.415444 -231.700324)
		(width 0.1016)
		(layer "F.Cu")
		(net "M_A_CPU0_SB_DQ<0>")
	)
	(segment
		(start 304.319178 -231.700324)
		(end 303.71923 -231.700324)
		(width 0.20066)
		(layer "F.Cu")
		(net "M_A_CPU0_SB_DQ<0>")
	)
	(segment
		(start 302.653446 -232.166668)
		(end 301.343314 -232.166668)
		(width 0.20066)
		(layer "F.Cu")
		(net "M_A_CPU0_SB_DQ<0>")
	)
	(segment
		(start 302.90516 -232.418382)
		(end 302.653446 -232.166668)
		(width 0.20066)
		(layer "F.Cu")
		(net "M_A_CPU0_SB_DQ<0>")
	)
	(segment
		(start 304.37328 -231.700324)
		(end 304.319178 -231.700324)
		(width 0.101854)
		(layer "F.Cu")
		(net "M_A_CPU0_SB_DQ<0>")
	)
	(segment
		(start 304.415444 -231.700324)
		(end 304.37328 -231.700324)
		(width 0.1016)
		(layer "F.Cu")
		(net "M_A_CPU0_SB_DQ<0>")
	)
	(segment
		(start 308.887114 -232.166668)
		(end 307.272944 -232.166668)
		(width 0.20066)
		(layer "F.Cu")
		(net "M_A_CPU0_SB_DQ<0>")
	)
	(segment
		(start 307.272944 -232.166668)
		(end 306.831746 -231.72547)
		(width 0.20066)
		(layer "F.Cu")
		(net "M_A_CPU0_SB_DQ<0>")
	)
	(segment
		(start 337.025234 -239.575086)
		(end 337.025234 -239.0394)
		(width 0.20066)
		(layer "F.Cu")
		(net "M_A_CPU0_SB_DQ<0>")
	)
	(segment
		(start 303.523396 -231.896158)
		(end 303.523396 -232.184194)
		(width 0.20066)
		(layer "F.Cu")
		(net "M_A_CPU0_SB_DQ<0>")
	)
	(segment
		(start 303.289208 -232.418382)
		(end 302.90516 -232.418382)
		(width 0.20066)
		(layer "F.Cu")
		(net "M_A_CPU0_SB_DQ<0>")
	)
	(segment
		(start 306.644294 -231.72547)
		(end 306.345844 -231.72547)
		(width 0.101854)
		(layer "F.Cu")
		(net "M_A_CPU0_SB_DQ<0>")
	)
	(segment
		(start 309.992014 -232.166668)
		(end 308.887114 -232.166668)
		(width 0.20066)
		(layer "F.Cu")
		(net "M_A_CPU0_SB_DQ<0>")
	)
	(segment
		(start 303.523396 -232.184194)
		(end 303.289208 -232.418382)
		(width 0.20066)
		(layer "F.Cu")
		(net "M_A_CPU0_SB_DQ<0>")
	)
	(segment
		(start 306.831746 -231.72547)
		(end 306.644294 -231.72547)
		(width 0.20066)
		(layer "F.Cu")
		(net "M_A_CPU0_SB_DQ<0>")
	)
	(segment
		(start 306.289202 -231.741726)
		(end 304.550826 -231.741726)
		(width 0.1016)
		(layer "F.Cu")
		(net "M_A_CPU0_SB_DQ<0>")
	)
	(segment
		(start 306.345844 -231.72547)
		(end 306.289202 -231.741726)
		(width 0.1016)
		(layer "F.Cu")
		(net "M_A_CPU0_SB_DQ<0>")
	)
	(segment
		(start 337.02498 -239.57534)
		(end 337.025234 -239.575086)
		(width 0.20066)
		(layer "F.Cu")
		(net "M_A_CPU0_SB_DQ<0>")
	)
	(segment
		(start 309.992014 -231.912414)
		(end 309.992014 -232.166668)
		(width 0.18288)
		(layer "In2.Cu")
		(net "M_A_CPU0_SB_DQ<0>")
	)
	(segment
		(start 336.367882 -239.528858)
		(end 336.35315 -239.537494)
		(width 0.088646)
		(layer "In2.Cu")
		(net "M_A_CPU0_SB_DQ<0>")
	)
	(segment
		(start 334.488282 -239.528858)
		(end 334.47355 -239.537494)
		(width 0.088646)
		(layer "In2.Cu")
		(net "M_A_CPU0_SB_DQ<0>")
	)
	(segment
		(start 333.548482 -239.528858)
		(end 333.53375 -239.537494)
		(width 0.088646)
		(layer "In2.Cu")
		(net "M_A_CPU0_SB_DQ<0>")
	)
	(segment
		(start 310.38927 -231.685846)
		(end 310.098186 -231.806242)
		(width 0.18288)
		(layer "In2.Cu")
		(net "M_A_CPU0_SB_DQ<0>")
	)
	(segment
		(start 335.428082 -239.528858)
		(end 335.41335 -239.537494)
		(width 0.088646)
		(layer "In2.Cu")
		(net "M_A_CPU0_SB_DQ<0>")
	)
	(segment
		(start 336.373978 -239.525302)
		(end 336.367882 -239.528858)
		(width 0.088646)
		(layer "In2.Cu")
		(net "M_A_CPU0_SB_DQ<0>")
	)
	(segment
		(start 312.097166 -231.684576)
		(end 311.904126 -231.491536)
		(width 0.18288)
		(layer "In2.Cu")
		(net "M_A_CPU0_SB_DQ<0>")
	)
	(segment
		(start 337.338162 -239.0394)
		(end 337.395312 -238.98225)
		(width 0.088646)
		(layer "In2.Cu")
		(net "M_A_CPU0_SB_DQ<0>")
	)
	(segment
		(start 313.863228 -231.684576)
		(end 312.097166 -231.684576)
		(width 0.18288)
		(layer "In2.Cu")
		(net "M_A_CPU0_SB_DQ<0>")
	)
	(segment
		(start 325.116952 -239.2807)
		(end 318.18453 -232.348278)
		(width 0.18288)
		(layer "In2.Cu")
		(net "M_A_CPU0_SB_DQ<0>")
	)
	(segment
		(start 314.006738 -231.744012)
		(end 313.863228 -231.684576)
		(width 0.18288)
		(layer "In2.Cu")
		(net "M_A_CPU0_SB_DQ<0>")
	)
	(segment
		(start 311.904126 -231.167178)
		(end 311.601358 -230.86441)
		(width 0.18288)
		(layer "In2.Cu")
		(net "M_A_CPU0_SB_DQ<0>")
	)
	(segment
		(start 336.838036 -238.715042)
		(end 336.829146 -238.720122)
		(width 0.088646)
		(layer "In2.Cu")
		(net "M_A_CPU0_SB_DQ<0>")
	)
	(segment
		(start 337.025234 -239.0394)
		(end 337.338162 -239.0394)
		(width 0.088646)
		(layer "In2.Cu")
		(net "M_A_CPU0_SB_DQ<0>")
	)
	(segment
		(start 318.18453 -232.348278)
		(end 315.834268 -232.348278)
		(width 0.18288)
		(layer "In2.Cu")
		(net "M_A_CPU0_SB_DQ<0>")
	)
	(segment
		(start 310.77535 -230.86441)
		(end 310.58231 -231.05745)
		(width 0.18288)
		(layer "In2.Cu")
		(net "M_A_CPU0_SB_DQ<0>")
	)
	(segment
		(start 331.138784 -239.2807)
		(end 330.699364 -239.2807)
		(width 0.088646)
		(layer "In2.Cu")
		(net "M_A_CPU0_SB_DQ<0>")
	)
	(segment
		(start 310.58231 -231.492806)
		(end 310.38927 -231.685846)
		(width 0.18288)
		(layer "In2.Cu")
		(net "M_A_CPU0_SB_DQ<0>")
	)
	(segment
		(start 314.375292 -231.744012)
		(end 314.006738 -231.744012)
		(width 0.18288)
		(layer "In2.Cu")
		(net "M_A_CPU0_SB_DQ<0>")
	)
	(segment
		(start 310.098186 -231.806242)
		(end 309.992014 -231.912414)
		(width 0.18288)
		(layer "In2.Cu")
		(net "M_A_CPU0_SB_DQ<0>")
	)
	(segment
		(start 310.58231 -231.05745)
		(end 310.58231 -231.492806)
		(width 0.18288)
		(layer "In2.Cu")
		(net "M_A_CPU0_SB_DQ<0>")
	)
	(segment
		(start 332.326488 -239.60455)
		(end 331.462634 -239.60455)
		(width 0.088646)
		(layer "In2.Cu")
		(net "M_A_CPU0_SB_DQ<0>")
	)
	(segment
		(start 330.699364 -239.2807)
		(end 325.116952 -239.2807)
		(width 0.18288)
		(layer "In2.Cu")
		(net "M_A_CPU0_SB_DQ<0>")
	)
	(segment
		(start 315.834268 -232.348278)
		(end 314.375292 -231.744012)
		(width 0.18288)
		(layer "In2.Cu")
		(net "M_A_CPU0_SB_DQ<0>")
	)
	(segment
		(start 311.904126 -231.491536)
		(end 311.904126 -231.167178)
		(width 0.18288)
		(layer "In2.Cu")
		(net "M_A_CPU0_SB_DQ<0>")
	)
	(segment
		(start 337.221322 -238.720122)
		(end 337.212432 -238.715042)
		(width 0.088646)
		(layer "In2.Cu")
		(net "M_A_CPU0_SB_DQ<0>")
	)
	(segment
		(start 331.462634 -239.60455)
		(end 331.138784 -239.2807)
		(width 0.088646)
		(layer "In2.Cu")
		(net "M_A_CPU0_SB_DQ<0>")
	)
	(segment
		(start 311.601358 -230.86441)
		(end 310.77535 -230.86441)
		(width 0.18288)
		(layer "In2.Cu")
		(net "M_A_CPU0_SB_DQ<0>")
	)
	(arc
		(start 336.829146 -238.720122)
		(mid 336.698232 -238.856482)
		(end 336.650584 -239.0394)
		(width 0.088646)
		(layer "In2.Cu")
		(net "M_A_CPU0_SB_DQ<0>")
	)
	(arc
		(start 334.862678 -239.528858)
		(mid 334.67548 -239.478715)
		(end 334.488282 -239.528858)
		(width 0.088646)
		(layer "In2.Cu")
		(net "M_A_CPU0_SB_DQ<0>")
	)
	(arc
		(start 332.983078 -239.528858)
		(mid 332.79588 -239.478715)
		(end 332.608682 -239.528858)
		(width 0.088646)
		(layer "In2.Cu")
		(net "M_A_CPU0_SB_DQ<0>")
	)
	(arc
		(start 337.212432 -238.715042)
		(mid 337.025234 -238.664899)
		(end 336.838036 -238.715042)
		(width 0.088646)
		(layer "In2.Cu")
		(net "M_A_CPU0_SB_DQ<0>")
	)
	(arc
		(start 336.35315 -239.537494)
		(mid 336.076675 -239.604814)
		(end 335.802478 -239.528858)
		(width 0.088646)
		(layer "In2.Cu")
		(net "M_A_CPU0_SB_DQ<0>")
	)
	(arc
		(start 333.53375 -239.537494)
		(mid 333.257275 -239.604814)
		(end 332.983078 -239.528858)
		(width 0.088646)
		(layer "In2.Cu")
		(net "M_A_CPU0_SB_DQ<0>")
	)
	(arc
		(start 334.47355 -239.537494)
		(mid 334.197075 -239.604814)
		(end 333.922878 -239.528858)
		(width 0.088646)
		(layer "In2.Cu")
		(net "M_A_CPU0_SB_DQ<0>")
	)
	(arc
		(start 336.650584 -239.0394)
		(mid 336.576593 -239.318966)
		(end 336.373978 -239.525302)
		(width 0.088646)
		(layer "In2.Cu")
		(net "M_A_CPU0_SB_DQ<0>")
	)
	(arc
		(start 337.395312 -238.98225)
		(mid 337.337193 -238.832009)
		(end 337.221322 -238.720122)
		(width 0.088646)
		(layer "In2.Cu")
		(net "M_A_CPU0_SB_DQ<0>")
	)
	(arc
		(start 333.922878 -239.528858)
		(mid 333.73568 -239.478715)
		(end 333.548482 -239.528858)
		(width 0.088646)
		(layer "In2.Cu")
		(net "M_A_CPU0_SB_DQ<0>")
	)
	(arc
		(start 335.41335 -239.537494)
		(mid 335.136875 -239.604814)
		(end 334.862678 -239.528858)
		(width 0.088646)
		(layer "In2.Cu")
		(net "M_A_CPU0_SB_DQ<0>")
	)
	(arc
		(start 335.802478 -239.528858)
		(mid 335.61528 -239.478715)
		(end 335.428082 -239.528858)
		(width 0.088646)
		(layer "In2.Cu")
		(net "M_A_CPU0_SB_DQ<0>")
	)
	(arc
		(start 332.608682 -239.528858)
		(mid 332.472558 -239.585234)
		(end 332.326488 -239.60455)
		(width 0.088646)
		(layer "In2.Cu")
		(net "M_A_CPU0_SB_DQ<0>")
	)
	(segment
		(start 332.89621 -244.196108)
		(end 332.133448 -244.196108)
		(width 0.088646)
		(layer "F.Cu")
		(net "M_A_CPU0_SB_CS_N<3>")
	)
	(segment
		(start 313.979306 -244.527832)
		(end 313.590432 -244.916706)
		(width 0.20066)
		(layer "F.Cu")
		(net "M_A_CPU0_SB_CS_N<3>")
	)
	(segment
		(start 319.690496 -244.528086)
		(end 315.232034 -244.528086)
		(width 0.20066)
		(layer "F.Cu")
		(net "M_A_CPU0_SB_CS_N<3>")
	)
	(segment
		(start 315.23178 -244.527832)
		(end 313.979306 -244.527832)
		(width 0.20066)
		(layer "F.Cu")
		(net "M_A_CPU0_SB_CS_N<3>")
	)
	(segment
		(start 321.960748 -245.470172)
		(end 321.110356 -245.117366)
		(width 0.1016)
		(layer "F.Cu")
		(net "M_A_CPU0_SB_CS_N<3>")
	)
	(segment
		(start 313.590432 -244.916706)
		(end 312.987182 -244.916706)
		(width 0.20066)
		(layer "F.Cu")
		(net "M_A_CPU0_SB_CS_N<3>")
	)
	(segment
		(start 332.133448 -244.196108)
		(end 332.096364 -244.233192)
		(width 0.088646)
		(layer "F.Cu")
		(net "M_A_CPU0_SB_CS_N<3>")
	)
	(segment
		(start 322.763388 -246.272812)
		(end 321.960748 -245.470172)
		(width 0.1016)
		(layer "F.Cu")
		(net "M_A_CPU0_SB_CS_N<3>")
	)
	(segment
		(start 321.097656 -245.112032)
		(end 319.690496 -244.528086)
		(width 0.20066)
		(layer "F.Cu")
		(net "M_A_CPU0_SB_CS_N<3>")
	)
	(segment
		(start 330.856336 -244.233192)
		(end 328.816716 -246.272812)
		(width 0.1016)
		(layer "F.Cu")
		(net "M_A_CPU0_SB_CS_N<3>")
	)
	(segment
		(start 333.137256 -244.096286)
		(end 332.89621 -244.196108)
		(width 0.088646)
		(layer "F.Cu")
		(net "M_A_CPU0_SB_CS_N<3>")
	)
	(segment
		(start 321.110356 -245.117366)
		(end 321.097656 -245.112032)
		(width 0.1016)
		(layer "F.Cu")
		(net "M_A_CPU0_SB_CS_N<3>")
	)
	(segment
		(start 328.816716 -246.272812)
		(end 322.763388 -246.272812)
		(width 0.1016)
		(layer "F.Cu")
		(net "M_A_CPU0_SB_CS_N<3>")
	)
	(segment
		(start 331.816964 -244.233192)
		(end 330.856336 -244.233192)
		(width 0.1016)
		(layer "F.Cu")
		(net "M_A_CPU0_SB_CS_N<3>")
	)
	(segment
		(start 334.675734 -243.644928)
		(end 334.224376 -244.096286)
		(width 0.088646)
		(layer "F.Cu")
		(net "M_A_CPU0_SB_CS_N<3>")
	)
	(segment
		(start 334.224376 -244.096286)
		(end 333.137256 -244.096286)
		(width 0.088646)
		(layer "F.Cu")
		(net "M_A_CPU0_SB_CS_N<3>")
	)
	(segment
		(start 332.096364 -244.233192)
		(end 331.816964 -244.233192)
		(width 0.088646)
		(layer "F.Cu")
		(net "M_A_CPU0_SB_CS_N<3>")
	)
	(segment
		(start 315.232034 -244.528086)
		(end 315.23178 -244.527832)
		(width 0.20066)
		(layer "F.Cu")
		(net "M_A_CPU0_SB_CS_N<3>")
	)
	(segment
		(start 329.069954 -246.882412)
		(end 322.355718 -246.882412)
		(width 0.1016)
		(layer "F.Cu")
		(net "M_A_CPU0_SB_CS_N<2>")
	)
	(segment
		(start 314.09005 -246.202454)
		(end 314.079128 -246.191532)
		(width 0.101854)
		(layer "F.Cu")
		(net "M_A_CPU0_SB_CS_N<2>")
	)
	(segment
		(start 310.061356 -245.76659)
		(end 308.887114 -245.76659)
		(width 0.20066)
		(layer "F.Cu")
		(net "M_A_CPU0_SB_CS_N<2>")
	)
	(segment
		(start 322.355718 -246.882412)
		(end 321.999102 -246.525796)
		(width 0.1016)
		(layer "F.Cu")
		(net "M_A_CPU0_SB_CS_N<2>")
	)
	(segment
		(start 333.004414 -244.744494)
		(end 332.975458 -244.715538)
		(width 0.088646)
		(layer "F.Cu")
		(net "M_A_CPU0_SB_CS_N<2>")
	)
	(segment
		(start 310.06161 -245.766336)
		(end 310.061356 -245.76659)
		(width 0.20066)
		(layer "F.Cu")
		(net "M_A_CPU0_SB_CS_N<2>")
	)
	(segment
		(start 332.975458 -244.715538)
		(end 332.537562 -244.715538)
		(width 0.088646)
		(layer "F.Cu")
		(net "M_A_CPU0_SB_CS_N<2>")
	)
	(segment
		(start 321.999102 -246.525796)
		(end 321.00901 -246.525796)
		(width 0.1016)
		(layer "F.Cu")
		(net "M_A_CPU0_SB_CS_N<2>")
	)
	(segment
		(start 310.50992 -246.214646)
		(end 310.06161 -245.766336)
		(width 0.20066)
		(layer "F.Cu")
		(net "M_A_CPU0_SB_CS_N<2>")
	)
	(segment
		(start 334.018636 -244.783102)
		(end 334.008222 -244.777006)
		(width 0.088646)
		(layer "F.Cu")
		(net "M_A_CPU0_SB_CS_N<2>")
	)
	(segment
		(start 311.948576 -246.191532)
		(end 311.925462 -246.214646)
		(width 0.101854)
		(layer "F.Cu")
		(net "M_A_CPU0_SB_CS_N<2>")
	)
	(segment
		(start 321.00901 -246.525796)
		(end 320.95313 -246.502682)
		(width 0.1016)
		(layer "F.Cu")
		(net "M_A_CPU0_SB_CS_N<2>")
	)
	(segment
		(start 314.493148 -246.202454)
		(end 314.12688 -246.202454)
		(width 0.20066)
		(layer "F.Cu")
		(net "M_A_CPU0_SB_CS_N<2>")
	)
	(segment
		(start 320.941192 -246.497856)
		(end 319.867026 -246.052594)
		(width 0.20066)
		(layer "F.Cu")
		(net "M_A_CPU0_SB_CS_N<2>")
	)
	(segment
		(start 314.079128 -246.191532)
		(end 311.948576 -246.191532)
		(width 0.1016)
		(layer "F.Cu")
		(net "M_A_CPU0_SB_CS_N<2>")
	)
	(segment
		(start 332.182724 -244.862604)
		(end 332.070964 -244.862604)
		(width 0.088646)
		(layer "F.Cu")
		(net "M_A_CPU0_SB_CS_N<2>")
	)
	(segment
		(start 332.070964 -244.862604)
		(end 331.089762 -244.862604)
		(width 0.1016)
		(layer "F.Cu")
		(net "M_A_CPU0_SB_CS_N<2>")
	)
	(segment
		(start 331.089762 -244.862604)
		(end 329.069954 -246.882412)
		(width 0.1016)
		(layer "F.Cu")
		(net "M_A_CPU0_SB_CS_N<2>")
	)
	(segment
		(start 334.790288 -244.55374)
		(end 334.393032 -244.783102)
		(width 0.088646)
		(layer "F.Cu")
		(net "M_A_CPU0_SB_CS_N<2>")
	)
	(segment
		(start 320.95313 -246.502682)
		(end 320.941192 -246.497856)
		(width 0.1016)
		(layer "F.Cu")
		(net "M_A_CPU0_SB_CS_N<2>")
	)
	(segment
		(start 311.91708 -246.214646)
		(end 310.50992 -246.214646)
		(width 0.20066)
		(layer "F.Cu")
		(net "M_A_CPU0_SB_CS_N<2>")
	)
	(segment
		(start 311.925462 -246.214646)
		(end 311.91708 -246.214646)
		(width 0.101854)
		(layer "F.Cu")
		(net "M_A_CPU0_SB_CS_N<2>")
	)
	(segment
		(start 314.12688 -246.202454)
		(end 314.09005 -246.202454)
		(width 0.101854)
		(layer "F.Cu")
		(net "M_A_CPU0_SB_CS_N<2>")
	)
	(segment
		(start 332.537562 -244.715538)
		(end 332.182724 -244.862604)
		(width 0.088646)
		(layer "F.Cu")
		(net "M_A_CPU0_SB_CS_N<2>")
	)
	(segment
		(start 319.867026 -246.052594)
		(end 314.643008 -246.052594)
		(width 0.20066)
		(layer "F.Cu")
		(net "M_A_CPU0_SB_CS_N<2>")
	)
	(segment
		(start 314.643008 -246.052594)
		(end 314.493148 -246.202454)
		(width 0.20066)
		(layer "F.Cu")
		(net "M_A_CPU0_SB_CS_N<2>")
	)
	(arc
		(start 333.078582 -244.783102)
		(mid 333.04193 -244.762968)
		(end 333.004414 -244.744494)
		(width 0.088646)
		(layer "F.Cu")
		(net "M_A_CPU0_SB_CS_N<2>")
	)
	(arc
		(start 334.008222 -244.777006)
		(mid 333.72979 -244.70716)
		(end 333.452978 -244.783102)
		(width 0.088646)
		(layer "F.Cu")
		(net "M_A_CPU0_SB_CS_N<2>")
	)
	(arc
		(start 335.14538 -244.458744)
		(mid 334.961578 -244.482864)
		(end 334.790288 -244.55374)
		(width 0.088646)
		(layer "F.Cu")
		(net "M_A_CPU0_SB_CS_N<2>")
	)
	(arc
		(start 334.393032 -244.783102)
		(mid 334.205834 -244.833245)
		(end 334.018636 -244.783102)
		(width 0.088646)
		(layer "F.Cu")
		(net "M_A_CPU0_SB_CS_N<2>")
	)
	(arc
		(start 333.452978 -244.783102)
		(mid 333.26578 -244.833245)
		(end 333.078582 -244.783102)
		(width 0.088646)
		(layer "F.Cu")
		(net "M_A_CPU0_SB_CS_N<2>")
	)
	(segment
		(start 333.735934 -243.644928)
		(end 333.478632 -243.90223)
		(width 0.088646)
		(layer "F.Cu")
		(net "M_A_CPU0_SB_CS_N<1>")
	)
	(segment
		(start 321.27825 -244.488462)
		(end 319.233804 -243.641626)
		(width 0.20066)
		(layer "F.Cu")
		(net "M_A_CPU0_SB_CS_N<1>")
	)
	(segment
		(start 307.865526 -244.476524)
		(end 307.85308 -244.476524)
		(width 0.101854)
		(layer "F.Cu")
		(net "M_A_CPU0_SB_CS_N<1>")
	)
	(segment
		(start 332.830932 -243.999258)
		(end 332.362048 -243.999258)
		(width 0.088646)
		(layer "F.Cu")
		(net "M_A_CPU0_SB_CS_N<1>")
	)
	(segment
		(start 314.17768 -243.641626)
		(end 311.86628 -243.641626)
		(width 0.1016)
		(layer "F.Cu")
		(net "M_A_CPU0_SB_CS_N<1>")
	)
	(segment
		(start 331.816964 -243.90223)
		(end 330.755752 -243.90223)
		(width 0.1016)
		(layer "F.Cu")
		(net "M_A_CPU0_SB_CS_N<1>")
	)
	(segment
		(start 307.85308 -244.476524)
		(end 307.297582 -244.476524)
		(width 0.20066)
		(layer "F.Cu")
		(net "M_A_CPU0_SB_CS_N<1>")
	)
	(segment
		(start 319.233804 -243.641626)
		(end 314.17768 -243.641626)
		(width 0.20066)
		(layer "F.Cu")
		(net "M_A_CPU0_SB_CS_N<1>")
	)
	(segment
		(start 332.362048 -243.999258)
		(end 332.12786 -243.90223)
		(width 0.088646)
		(layer "F.Cu")
		(net "M_A_CPU0_SB_CS_N<1>")
	)
	(segment
		(start 307.880512 -244.49151)
		(end 307.865526 -244.476524)
		(width 0.101854)
		(layer "F.Cu")
		(net "M_A_CPU0_SB_CS_N<1>")
	)
	(segment
		(start 333.06512 -243.90223)
		(end 332.830932 -243.999258)
		(width 0.088646)
		(layer "F.Cu")
		(net "M_A_CPU0_SB_CS_N<1>")
	)
	(segment
		(start 322.97116 -245.968012)
		(end 321.642486 -244.639338)
		(width 0.1016)
		(layer "F.Cu")
		(net "M_A_CPU0_SB_CS_N<1>")
	)
	(segment
		(start 310.695848 -243.816632)
		(end 310.695848 -244.086634)
		(width 0.20066)
		(layer "F.Cu")
		(net "M_A_CPU0_SB_CS_N<1>")
	)
	(segment
		(start 311.86628 -243.641626)
		(end 311.75198 -243.641626)
		(width 0.101854)
		(layer "F.Cu")
		(net "M_A_CPU0_SB_CS_N<1>")
	)
	(segment
		(start 333.478632 -243.90223)
		(end 333.06512 -243.90223)
		(width 0.088646)
		(layer "F.Cu")
		(net "M_A_CPU0_SB_CS_N<1>")
	)
	(segment
		(start 307.297582 -244.476524)
		(end 306.8574 -244.916706)
		(width 0.20066)
		(layer "F.Cu")
		(net "M_A_CPU0_SB_CS_N<1>")
	)
	(segment
		(start 306.8574 -244.916706)
		(end 305.443382 -244.916706)
		(width 0.20066)
		(layer "F.Cu")
		(net "M_A_CPU0_SB_CS_N<1>")
	)
	(segment
		(start 310.01208 -244.49151)
		(end 307.880512 -244.49151)
		(width 0.1016)
		(layer "F.Cu")
		(net "M_A_CPU0_SB_CS_N<1>")
	)
	(segment
		(start 310.290972 -244.49151)
		(end 310.072786 -244.49151)
		(width 0.20066)
		(layer "F.Cu")
		(net "M_A_CPU0_SB_CS_N<1>")
	)
	(segment
		(start 311.75198 -243.641626)
		(end 310.870854 -243.641626)
		(width 0.20066)
		(layer "F.Cu")
		(net "M_A_CPU0_SB_CS_N<1>")
	)
	(segment
		(start 310.695848 -244.086634)
		(end 310.290972 -244.49151)
		(width 0.20066)
		(layer "F.Cu")
		(net "M_A_CPU0_SB_CS_N<1>")
	)
	(segment
		(start 330.755752 -243.90223)
		(end 328.68997 -245.968012)
		(width 0.1016)
		(layer "F.Cu")
		(net "M_A_CPU0_SB_CS_N<1>")
	)
	(segment
		(start 310.072786 -244.49151)
		(end 310.01208 -244.49151)
		(width 0.101854)
		(layer "F.Cu")
		(net "M_A_CPU0_SB_CS_N<1>")
	)
	(segment
		(start 310.870854 -243.641626)
		(end 310.695848 -243.816632)
		(width 0.20066)
		(layer "F.Cu")
		(net "M_A_CPU0_SB_CS_N<1>")
	)
	(segment
		(start 328.68997 -245.968012)
		(end 322.97116 -245.968012)
		(width 0.1016)
		(layer "F.Cu")
		(net "M_A_CPU0_SB_CS_N<1>")
	)
	(segment
		(start 321.642486 -244.639338)
		(end 321.27825 -244.488462)
		(width 0.1016)
		(layer "F.Cu")
		(net "M_A_CPU0_SB_CS_N<1>")
	)
	(segment
		(start 332.12786 -243.90223)
		(end 331.816964 -243.90223)
		(width 0.088646)
		(layer "F.Cu")
		(net "M_A_CPU0_SB_CS_N<1>")
	)
	(segment
		(start 328.943208 -246.577612)
		(end 330.981304 -244.539516)
		(width 0.1016)
		(layer "F.Cu")
		(net "M_A_CPU0_SB_CS_N<0>")
	)
	(segment
		(start 311.966102 -245.326662)
		(end 311.981088 -245.341648)
		(width 0.101854)
		(layer "F.Cu")
		(net "M_A_CPU0_SB_CS_N<0>")
	)
	(segment
		(start 321.210178 -245.890796)
		(end 321.9196 -245.890796)
		(width 0.1016)
		(layer "F.Cu")
		(net "M_A_CPU0_SB_CS_N<0>")
	)
	(segment
		(start 306.55768 -245.332504)
		(end 306.710334 -245.332504)
		(width 0.20066)
		(layer "F.Cu")
		(net "M_A_CPU0_SB_CS_N<0>")
	)
	(segment
		(start 304.110644 -245.333774)
		(end 304.42408 -245.333774)
		(width 0.20066)
		(layer "F.Cu")
		(net "M_A_CPU0_SB_CS_N<0>")
	)
	(segment
		(start 319.857628 -245.330472)
		(end 321.073272 -245.834154)
		(width 0.20066)
		(layer "F.Cu")
		(net "M_A_CPU0_SB_CS_N<0>")
	)
	(segment
		(start 306.50434 -245.341648)
		(end 306.513484 -245.332504)
		(width 0.101854)
		(layer "F.Cu")
		(net "M_A_CPU0_SB_CS_N<0>")
	)
	(segment
		(start 310.01208 -245.355618)
		(end 311.632346 -245.355618)
		(width 0.20066)
		(layer "F.Cu")
		(net "M_A_CPU0_SB_CS_N<0>")
	)
	(segment
		(start 321.9196 -245.890796)
		(end 322.606416 -246.577612)
		(width 0.1016)
		(layer "F.Cu")
		(net "M_A_CPU0_SB_CS_N<0>")
	)
	(segment
		(start 332.148942 -244.539516)
		(end 332.229714 -244.458744)
		(width 0.088646)
		(layer "F.Cu")
		(net "M_A_CPU0_SB_CS_N<0>")
	)
	(segment
		(start 303.18329 -244.708172)
		(end 303.57191 -244.708172)
		(width 0.20066)
		(layer "F.Cu")
		(net "M_A_CPU0_SB_CS_N<0>")
	)
	(segment
		(start 307.910992 -245.341648)
		(end 309.933848 -245.341648)
		(width 0.1016)
		(layer "F.Cu")
		(net "M_A_CPU0_SB_CS_N<0>")
	)
	(segment
		(start 314.09132 -245.341648)
		(end 314.102496 -245.330472)
		(width 0.101854)
		(layer "F.Cu")
		(net "M_A_CPU0_SB_CS_N<0>")
	)
	(segment
		(start 303.74717 -244.883432)
		(end 303.74717 -244.9703)
		(width 0.20066)
		(layer "F.Cu")
		(net "M_A_CPU0_SB_CS_N<0>")
	)
	(segment
		(start 321.096894 -245.843806)
		(end 321.210178 -245.890796)
		(width 0.1016)
		(layer "F.Cu")
		(net "M_A_CPU0_SB_CS_N<0>")
	)
	(segment
		(start 331.816964 -244.539516)
		(end 332.148942 -244.539516)
		(width 0.088646)
		(layer "F.Cu")
		(net "M_A_CPU0_SB_CS_N<0>")
	)
	(segment
		(start 302.632872 -245.76659)
		(end 303.00803 -245.391432)
		(width 0.20066)
		(layer "F.Cu")
		(net "M_A_CPU0_SB_CS_N<0>")
	)
	(segment
		(start 330.981304 -244.539516)
		(end 331.816964 -244.539516)
		(width 0.1016)
		(layer "F.Cu")
		(net "M_A_CPU0_SB_CS_N<0>")
	)
	(segment
		(start 307.85308 -245.358412)
		(end 307.894228 -245.358412)
		(width 0.101854)
		(layer "F.Cu")
		(net "M_A_CPU0_SB_CS_N<0>")
	)
	(segment
		(start 303.74717 -244.9703)
		(end 304.110644 -245.333774)
		(width 0.20066)
		(layer "F.Cu")
		(net "M_A_CPU0_SB_CS_N<0>")
	)
	(segment
		(start 321.073272 -245.834154)
		(end 321.08521 -245.83898)
		(width 0.101854)
		(layer "F.Cu")
		(net "M_A_CPU0_SB_CS_N<0>")
	)
	(segment
		(start 307.894228 -245.358412)
		(end 307.910992 -245.341648)
		(width 0.101854)
		(layer "F.Cu")
		(net "M_A_CPU0_SB_CS_N<0>")
	)
	(segment
		(start 303.00803 -245.391432)
		(end 303.00803 -244.883432)
		(width 0.20066)
		(layer "F.Cu")
		(net "M_A_CPU0_SB_CS_N<0>")
	)
	(segment
		(start 322.606416 -246.577612)
		(end 328.943208 -246.577612)
		(width 0.1016)
		(layer "F.Cu")
		(net "M_A_CPU0_SB_CS_N<0>")
	)
	(segment
		(start 303.00803 -244.883432)
		(end 303.18329 -244.708172)
		(width 0.20066)
		(layer "F.Cu")
		(net "M_A_CPU0_SB_CS_N<0>")
	)
	(segment
		(start 332.229714 -244.458744)
		(end 333.26578 -244.458744)
		(width 0.088646)
		(layer "F.Cu")
		(net "M_A_CPU0_SB_CS_N<0>")
	)
	(segment
		(start 304.449226 -245.333774)
		(end 304.4571 -245.341648)
		(width 0.101854)
		(layer "F.Cu")
		(net "M_A_CPU0_SB_CS_N<0>")
	)
	(segment
		(start 304.42408 -245.333774)
		(end 304.449226 -245.333774)
		(width 0.101854)
		(layer "F.Cu")
		(net "M_A_CPU0_SB_CS_N<0>")
	)
	(segment
		(start 301.343314 -245.76659)
		(end 302.632872 -245.76659)
		(width 0.20066)
		(layer "F.Cu")
		(net "M_A_CPU0_SB_CS_N<0>")
	)
	(segment
		(start 306.736242 -245.358412)
		(end 307.85308 -245.358412)
		(width 0.20066)
		(layer "F.Cu")
		(net "M_A_CPU0_SB_CS_N<0>")
	)
	(segment
		(start 303.57191 -244.708172)
		(end 303.74717 -244.883432)
		(width 0.20066)
		(layer "F.Cu")
		(net "M_A_CPU0_SB_CS_N<0>")
	)
	(segment
		(start 311.94248 -245.326662)
		(end 311.966102 -245.326662)
		(width 0.101854)
		(layer "F.Cu")
		(net "M_A_CPU0_SB_CS_N<0>")
	)
	(segment
		(start 314.102496 -245.330472)
		(end 314.12688 -245.330472)
		(width 0.101854)
		(layer "F.Cu")
		(net "M_A_CPU0_SB_CS_N<0>")
	)
	(segment
		(start 304.4571 -245.341648)
		(end 306.50434 -245.341648)
		(width 0.1016)
		(layer "F.Cu")
		(net "M_A_CPU0_SB_CS_N<0>")
	)
	(segment
		(start 314.12688 -245.330472)
		(end 319.857628 -245.330472)
		(width 0.20066)
		(layer "F.Cu")
		(net "M_A_CPU0_SB_CS_N<0>")
	)
	(segment
		(start 321.08521 -245.83898)
		(end 321.096894 -245.843806)
		(width 0.1016)
		(layer "F.Cu")
		(net "M_A_CPU0_SB_CS_N<0>")
	)
	(segment
		(start 309.947818 -245.355618)
		(end 310.01208 -245.355618)
		(width 0.101854)
		(layer "F.Cu")
		(net "M_A_CPU0_SB_CS_N<0>")
	)
	(segment
		(start 311.981088 -245.341648)
		(end 314.09132 -245.341648)
		(width 0.1016)
		(layer "F.Cu")
		(net "M_A_CPU0_SB_CS_N<0>")
	)
	(segment
		(start 309.933848 -245.341648)
		(end 309.947818 -245.355618)
		(width 0.101854)
		(layer "F.Cu")
		(net "M_A_CPU0_SB_CS_N<0>")
	)
	(segment
		(start 306.710334 -245.332504)
		(end 306.736242 -245.358412)
		(width 0.20066)
		(layer "F.Cu")
		(net "M_A_CPU0_SB_CS_N<0>")
	)
	(segment
		(start 306.513484 -245.332504)
		(end 306.55768 -245.332504)
		(width 0.101854)
		(layer "F.Cu")
		(net "M_A_CPU0_SB_CS_N<0>")
	)
	(segment
		(start 311.632346 -245.355618)
		(end 311.661302 -245.326662)
		(width 0.20066)
		(layer "F.Cu")
		(net "M_A_CPU0_SB_CS_N<0>")
	)
	(segment
		(start 311.661302 -245.326662)
		(end 311.94248 -245.326662)
		(width 0.20066)
		(layer "F.Cu")
		(net "M_A_CPU0_SB_CS_N<0>")
	)
	(segment
		(start 331.016864 -240.886996)
		(end 330.92263 -240.98123)
		(width 0.088646)
		(layer "F.Cu")
		(net "M_A_CPU0_SB_CB<7>")
	)
	(segment
		(start 310.49214 -239.391698)
		(end 310.67248 -239.211358)
		(width 0.20066)
		(layer "F.Cu")
		(net "M_A_CPU0_SB_CB<7>")
	)
	(segment
		(start 328.33183 -241.389154)
		(end 328.13117 -241.589814)
		(width 0.20066)
		(layer "F.Cu")
		(net "M_A_CPU0_SB_CB<7>")
	)
	(segment
		(start 327.62063 -241.389154)
		(end 327.62063 -241.280442)
		(width 0.20066)
		(layer "F.Cu")
		(net "M_A_CPU0_SB_CB<7>")
	)
	(segment
		(start 315.604652 -239.67567)
		(end 314.895738 -238.966756)
		(width 0.20066)
		(layer "F.Cu")
		(net "M_A_CPU0_SB_CB<7>")
	)
	(segment
		(start 325.68769 -241.079782)
		(end 325.48703 -241.280442)
		(width 0.20066)
		(layer "F.Cu")
		(net "M_A_CPU0_SB_CB<7>")
	)
	(segment
		(start 335.488026 -241.070384)
		(end 335.488026 -240.894362)
		(width 0.088646)
		(layer "F.Cu")
		(net "M_A_CPU0_SB_CB<7>")
	)
	(segment
		(start 329.04303 -241.353848)
		(end 329.04303 -241.280442)
		(width 0.20066)
		(layer "F.Cu")
		(net "M_A_CPU0_SB_CB<7>")
	)
	(segment
		(start 310.776366 -238.75365)
		(end 311.060592 -238.75365)
		(width 0.20066)
		(layer "F.Cu")
		(net "M_A_CPU0_SB_CB<7>")
	)
	(segment
		(start 330.349352 -241.554508)
		(end 329.657964 -241.554508)
		(width 0.1016)
		(layer "F.Cu")
		(net "M_A_CPU0_SB_CB<7>")
	)
	(segment
		(start 323.790564 -241.554508)
		(end 323.28866 -241.554508)
		(width 0.20066)
		(layer "F.Cu")
		(net "M_A_CPU0_SB_CB<7>")
	)
	(segment
		(start 325.48703 -241.389154)
		(end 325.28637 -241.589814)
		(width 0.20066)
		(layer "F.Cu")
		(net "M_A_CPU0_SB_CB<7>")
	)
	(segment
		(start 310.01208 -239.391698)
		(end 310.366918 -239.391698)
		(width 0.101854)
		(layer "F.Cu")
		(net "M_A_CPU0_SB_CB<7>")
	)
	(segment
		(start 326.90943 -241.353848)
		(end 326.70877 -241.554508)
		(width 0.20066)
		(layer "F.Cu")
		(net "M_A_CPU0_SB_CB<7>")
	)
	(segment
		(start 310.366918 -239.391698)
		(end 310.49214 -239.391698)
		(width 0.20066)
		(layer "F.Cu")
		(net "M_A_CPU0_SB_CB<7>")
	)
	(segment
		(start 332.206092 -240.886996)
		(end 331.016864 -240.886996)
		(width 0.088646)
		(layer "F.Cu")
		(net "M_A_CPU0_SB_CB<7>")
	)
	(segment
		(start 329.24369 -241.554508)
		(end 329.04303 -241.353848)
		(width 0.20066)
		(layer "F.Cu")
		(net "M_A_CPU0_SB_CB<7>")
	)
	(segment
		(start 305.443382 -238.966756)
		(end 306.973224 -238.966756)
		(width 0.20066)
		(layer "F.Cu")
		(net "M_A_CPU0_SB_CB<7>")
	)
	(segment
		(start 310.67248 -238.857536)
		(end 310.776366 -238.75365)
		(width 0.20066)
		(layer "F.Cu")
		(net "M_A_CPU0_SB_CB<7>")
	)
	(segment
		(start 329.657964 -241.554508)
		(end 329.24369 -241.554508)
		(width 0.20066)
		(layer "F.Cu")
		(net "M_A_CPU0_SB_CB<7>")
	)
	(segment
		(start 322.812156 -241.078004)
		(end 319.426082 -239.67567)
		(width 0.20066)
		(layer "F.Cu")
		(net "M_A_CPU0_SB_CB<7>")
	)
	(segment
		(start 307.398166 -239.391698)
		(end 307.455316 -239.391698)
		(width 0.20066)
		(layer "F.Cu")
		(net "M_A_CPU0_SB_CB<7>")
	)
	(segment
		(start 307.80228 -239.391698)
		(end 310.01208 -239.391698)
		(width 0.1016)
		(layer "F.Cu")
		(net "M_A_CPU0_SB_CB<7>")
	)
	(segment
		(start 330.92263 -240.98123)
		(end 330.349352 -241.554508)
		(width 0.1016)
		(layer "F.Cu")
		(net "M_A_CPU0_SB_CB<7>")
	)
	(segment
		(start 314.895738 -238.966756)
		(end 312.987182 -238.966756)
		(width 0.20066)
		(layer "F.Cu")
		(net "M_A_CPU0_SB_CB<7>")
	)
	(segment
		(start 328.53249 -241.079782)
		(end 328.33183 -241.280442)
		(width 0.20066)
		(layer "F.Cu")
		(net "M_A_CPU0_SB_CB<7>")
	)
	(segment
		(start 324.77583 -241.280442)
		(end 324.57517 -241.079782)
		(width 0.20066)
		(layer "F.Cu")
		(net "M_A_CPU0_SB_CB<7>")
	)
	(segment
		(start 324.26529 -241.079782)
		(end 323.790564 -241.554508)
		(width 0.20066)
		(layer "F.Cu")
		(net "M_A_CPU0_SB_CB<7>")
	)
	(segment
		(start 327.62063 -241.280442)
		(end 327.41997 -241.079782)
		(width 0.20066)
		(layer "F.Cu")
		(net "M_A_CPU0_SB_CB<7>")
	)
	(segment
		(start 325.99757 -241.079782)
		(end 325.68769 -241.079782)
		(width 0.20066)
		(layer "F.Cu")
		(net "M_A_CPU0_SB_CB<7>")
	)
	(segment
		(start 328.84237 -241.079782)
		(end 328.53249 -241.079782)
		(width 0.20066)
		(layer "F.Cu")
		(net "M_A_CPU0_SB_CB<7>")
	)
	(segment
		(start 332.784704 -240.958116)
		(end 332.277212 -240.958116)
		(width 0.088646)
		(layer "F.Cu")
		(net "M_A_CPU0_SB_CB<7>")
	)
	(segment
		(start 327.11009 -241.079782)
		(end 326.90943 -241.280442)
		(width 0.20066)
		(layer "F.Cu")
		(net "M_A_CPU0_SB_CB<7>")
	)
	(segment
		(start 332.277212 -240.958116)
		(end 332.206092 -240.886996)
		(width 0.088646)
		(layer "F.Cu")
		(net "M_A_CPU0_SB_CB<7>")
	)
	(segment
		(start 335.355184 -241.203226)
		(end 335.488026 -241.070384)
		(width 0.088646)
		(layer "F.Cu")
		(net "M_A_CPU0_SB_CB<7>")
	)
	(segment
		(start 335.488026 -240.894362)
		(end 335.41081 -240.817146)
		(width 0.088646)
		(layer "F.Cu")
		(net "M_A_CPU0_SB_CB<7>")
	)
	(segment
		(start 326.19823 -241.280442)
		(end 325.99757 -241.079782)
		(width 0.20066)
		(layer "F.Cu")
		(net "M_A_CPU0_SB_CB<7>")
	)
	(segment
		(start 311.060592 -238.75365)
		(end 311.273698 -238.966756)
		(width 0.20066)
		(layer "F.Cu")
		(net "M_A_CPU0_SB_CB<7>")
	)
	(segment
		(start 310.67248 -239.211358)
		(end 310.67248 -238.857536)
		(width 0.20066)
		(layer "F.Cu")
		(net "M_A_CPU0_SB_CB<7>")
	)
	(segment
		(start 323.28866 -241.554508)
		(end 322.812156 -241.078004)
		(width 0.20066)
		(layer "F.Cu")
		(net "M_A_CPU0_SB_CB<7>")
	)
	(segment
		(start 324.97649 -241.589814)
		(end 324.77583 -241.389154)
		(width 0.20066)
		(layer "F.Cu")
		(net "M_A_CPU0_SB_CB<7>")
	)
	(segment
		(start 324.57517 -241.079782)
		(end 324.26529 -241.079782)
		(width 0.20066)
		(layer "F.Cu")
		(net "M_A_CPU0_SB_CB<7>")
	)
	(segment
		(start 326.70877 -241.554508)
		(end 326.39889 -241.554508)
		(width 0.20066)
		(layer "F.Cu")
		(net "M_A_CPU0_SB_CB<7>")
	)
	(segment
		(start 333.203804 -240.816892)
		(end 333.067152 -240.88217)
		(width 0.088646)
		(layer "F.Cu")
		(net "M_A_CPU0_SB_CB<7>")
	)
	(segment
		(start 324.77583 -241.389154)
		(end 324.77583 -241.280442)
		(width 0.20066)
		(layer "F.Cu")
		(net "M_A_CPU0_SB_CB<7>")
	)
	(segment
		(start 328.33183 -241.280442)
		(end 328.33183 -241.389154)
		(width 0.20066)
		(layer "F.Cu")
		(net "M_A_CPU0_SB_CB<7>")
	)
	(segment
		(start 306.973224 -238.966756)
		(end 307.398166 -239.391698)
		(width 0.20066)
		(layer "F.Cu")
		(net "M_A_CPU0_SB_CB<7>")
	)
	(segment
		(start 334.393032 -240.878868)
		(end 334.325976 -240.84026)
		(width 0.088646)
		(layer "F.Cu")
		(net "M_A_CPU0_SB_CB<7>")
	)
	(segment
		(start 334.173068 -240.799366)
		(end 333.28102 -240.799366)
		(width 0.088646)
		(layer "F.Cu")
		(net "M_A_CPU0_SB_CB<7>")
	)
	(segment
		(start 325.48703 -241.280442)
		(end 325.48703 -241.389154)
		(width 0.20066)
		(layer "F.Cu")
		(net "M_A_CPU0_SB_CB<7>")
	)
	(segment
		(start 307.455316 -239.391698)
		(end 307.80228 -239.391698)
		(width 0.101854)
		(layer "F.Cu")
		(net "M_A_CPU0_SB_CB<7>")
	)
	(segment
		(start 319.426082 -239.67567)
		(end 315.604652 -239.67567)
		(width 0.20066)
		(layer "F.Cu")
		(net "M_A_CPU0_SB_CB<7>")
	)
	(segment
		(start 326.19823 -241.353848)
		(end 326.19823 -241.280442)
		(width 0.20066)
		(layer "F.Cu")
		(net "M_A_CPU0_SB_CB<7>")
	)
	(segment
		(start 326.39889 -241.554508)
		(end 326.19823 -241.353848)
		(width 0.20066)
		(layer "F.Cu")
		(net "M_A_CPU0_SB_CB<7>")
	)
	(segment
		(start 327.41997 -241.079782)
		(end 327.11009 -241.079782)
		(width 0.20066)
		(layer "F.Cu")
		(net "M_A_CPU0_SB_CB<7>")
	)
	(segment
		(start 328.13117 -241.589814)
		(end 327.82129 -241.589814)
		(width 0.20066)
		(layer "F.Cu")
		(net "M_A_CPU0_SB_CB<7>")
	)
	(segment
		(start 327.82129 -241.589814)
		(end 327.62063 -241.389154)
		(width 0.20066)
		(layer "F.Cu")
		(net "M_A_CPU0_SB_CB<7>")
	)
	(segment
		(start 325.28637 -241.589814)
		(end 324.97649 -241.589814)
		(width 0.20066)
		(layer "F.Cu")
		(net "M_A_CPU0_SB_CB<7>")
	)
	(segment
		(start 311.273698 -238.966756)
		(end 312.987182 -238.966756)
		(width 0.20066)
		(layer "F.Cu")
		(net "M_A_CPU0_SB_CB<7>")
	)
	(segment
		(start 335.41081 -240.817146)
		(end 335.111344 -240.817146)
		(width 0.088646)
		(layer "F.Cu")
		(net "M_A_CPU0_SB_CB<7>")
	)
	(segment
		(start 334.949292 -240.88344)
		(end 334.843628 -240.942114)
		(width 0.088646)
		(layer "F.Cu")
		(net "M_A_CPU0_SB_CB<7>")
	)
	(segment
		(start 326.90943 -241.280442)
		(end 326.90943 -241.353848)
		(width 0.20066)
		(layer "F.Cu")
		(net "M_A_CPU0_SB_CB<7>")
	)
	(segment
		(start 335.021936 -240.841276)
		(end 334.95869 -240.878106)
		(width 0.088646)
		(layer "F.Cu")
		(net "M_A_CPU0_SB_CB<7>")
	)
	(segment
		(start 329.04303 -241.280442)
		(end 328.84237 -241.079782)
		(width 0.20066)
		(layer "F.Cu")
		(net "M_A_CPU0_SB_CB<7>")
	)
	(segment
		(start 335.14538 -241.203226)
		(end 335.355184 -241.203226)
		(width 0.088646)
		(layer "F.Cu")
		(net "M_A_CPU0_SB_CB<7>")
	)
	(arc
		(start 334.843628 -240.942114)
		(mid 334.607735 -240.985925)
		(end 334.393032 -240.878868)
		(width 0.088646)
		(layer "F.Cu")
		(net "M_A_CPU0_SB_CB<7>")
	)
	(arc
		(start 333.28102 -240.799366)
		(mid 333.241425 -240.803792)
		(end 333.203804 -240.816892)
		(width 0.088646)
		(layer "F.Cu")
		(net "M_A_CPU0_SB_CB<7>")
	)
	(arc
		(start 334.95869 -240.878106)
		(mid 334.954003 -240.880795)
		(end 334.949292 -240.88344)
		(width 0.088646)
		(layer "F.Cu")
		(net "M_A_CPU0_SB_CB<7>")
	)
	(arc
		(start 334.325976 -240.84026)
		(mid 334.252205 -240.809792)
		(end 334.173068 -240.799366)
		(width 0.088646)
		(layer "F.Cu")
		(net "M_A_CPU0_SB_CB<7>")
	)
	(arc
		(start 335.111344 -240.817146)
		(mid 335.065043 -240.823289)
		(end 335.021936 -240.841276)
		(width 0.088646)
		(layer "F.Cu")
		(net "M_A_CPU0_SB_CB<7>")
	)
	(arc
		(start 333.067152 -240.88217)
		(mid 332.930926 -240.938727)
		(end 332.784704 -240.958116)
		(width 0.088646)
		(layer "F.Cu")
		(net "M_A_CPU0_SB_CB<7>")
	)
	(segment
		(start 328.02703 -242.884706)
		(end 327.82637 -243.085366)
		(width 0.20066)
		(layer "F.Cu")
		(net "M_A_CPU0_SB_CB<6>")
	)
	(segment
		(start 314.617354 -240.507266)
		(end 314.333128 -240.507266)
		(width 0.20066)
		(layer "F.Cu")
		(net "M_A_CPU0_SB_CB<6>")
	)
	(segment
		(start 334.675734 -242.017042)
		(end 334.018382 -241.744754)
		(width 0.088646)
		(layer "F.Cu")
		(net "M_A_CPU0_SB_CB<6>")
	)
	(segment
		(start 324.98157 -243.214906)
		(end 324.78091 -243.415566)
		(width 0.20066)
		(layer "F.Cu")
		(net "M_A_CPU0_SB_CB<6>")
	)
	(segment
		(start 310.01208 -241.09172)
		(end 310.153558 -241.09172)
		(width 0.101854)
		(layer "F.Cu")
		(net "M_A_CPU0_SB_CB<6>")
	)
	(segment
		(start 328.53757 -243.214906)
		(end 328.53757 -243.085366)
		(width 0.20066)
		(layer "F.Cu")
		(net "M_A_CPU0_SB_CB<6>")
	)
	(segment
		(start 331.279754 -241.486944)
		(end 329.89774 -242.868958)
		(width 0.1016)
		(layer "F.Cu")
		(net "M_A_CPU0_SB_CB<6>")
	)
	(segment
		(start 311.196482 -240.483898)
		(end 311.379362 -240.666778)
		(width 0.20066)
		(layer "F.Cu")
		(net "M_A_CPU0_SB_CB<6>")
	)
	(segment
		(start 333.568294 -241.546126)
		(end 333.479394 -241.635026)
		(width 0.088646)
		(layer "F.Cu")
		(net "M_A_CPU0_SB_CB<6>")
	)
	(segment
		(start 314.173616 -240.666778)
		(end 312.987182 -240.666778)
		(width 0.20066)
		(layer "F.Cu")
		(net "M_A_CPU0_SB_CB<6>")
	)
	(segment
		(start 327.62571 -243.415566)
		(end 327.31583 -243.415566)
		(width 0.20066)
		(layer "F.Cu")
		(net "M_A_CPU0_SB_CB<6>")
	)
	(segment
		(start 322.830444 -243.415566)
		(end 321.55384 -242.138962)
		(width 0.20066)
		(layer "F.Cu")
		(net "M_A_CPU0_SB_CB<6>")
	)
	(segment
		(start 310.609996 -241.001804)
		(end 310.609996 -240.610898)
		(width 0.20066)
		(layer "F.Cu")
		(net "M_A_CPU0_SB_CB<6>")
	)
	(segment
		(start 325.69277 -243.085366)
		(end 325.49211 -242.884706)
		(width 0.20066)
		(layer "F.Cu")
		(net "M_A_CPU0_SB_CB<6>")
	)
	(segment
		(start 329.89774 -242.868958)
		(end 329.89774 -242.870482)
		(width 0.1016)
		(layer "F.Cu")
		(net "M_A_CPU0_SB_CB<6>")
	)
	(segment
		(start 333.568294 -241.433858)
		(end 333.568294 -241.546126)
		(width 0.088646)
		(layer "F.Cu")
		(net "M_A_CPU0_SB_CB<6>")
	)
	(segment
		(start 325.69277 -243.214906)
		(end 325.69277 -243.085366)
		(width 0.20066)
		(layer "F.Cu")
		(net "M_A_CPU0_SB_CB<6>")
	)
	(segment
		(start 326.20331 -243.415566)
		(end 325.89343 -243.415566)
		(width 0.20066)
		(layer "F.Cu")
		(net "M_A_CPU0_SB_CB<6>")
	)
	(segment
		(start 333.809594 -241.34318)
		(end 333.658972 -241.34318)
		(width 0.088646)
		(layer "F.Cu")
		(net "M_A_CPU0_SB_CB<6>")
	)
	(segment
		(start 326.40397 -243.214906)
		(end 326.20331 -243.415566)
		(width 0.20066)
		(layer "F.Cu")
		(net "M_A_CPU0_SB_CB<6>")
	)
	(segment
		(start 333.898494 -241.43208)
		(end 333.809594 -241.34318)
		(width 0.088646)
		(layer "F.Cu")
		(net "M_A_CPU0_SB_CB<6>")
	)
	(segment
		(start 305.443382 -240.666778)
		(end 307.170328 -240.666778)
		(width 0.20066)
		(layer "F.Cu")
		(net "M_A_CPU0_SB_CB<6>")
	)
	(segment
		(start 323.55917 -243.214906)
		(end 323.35851 -243.415566)
		(width 0.20066)
		(layer "F.Cu")
		(net "M_A_CPU0_SB_CB<6>")
	)
	(segment
		(start 323.35851 -243.415566)
		(end 322.830444 -243.415566)
		(width 0.20066)
		(layer "F.Cu")
		(net "M_A_CPU0_SB_CB<6>")
	)
	(segment
		(start 310.609996 -240.610898)
		(end 310.736996 -240.483898)
		(width 0.20066)
		(layer "F.Cu")
		(net "M_A_CPU0_SB_CB<6>")
	)
	(segment
		(start 324.98157 -243.085366)
		(end 324.98157 -243.214906)
		(width 0.20066)
		(layer "F.Cu")
		(net "M_A_CPU0_SB_CB<6>")
	)
	(segment
		(start 314.333128 -240.507266)
		(end 314.173616 -240.666778)
		(width 0.20066)
		(layer "F.Cu")
		(net "M_A_CPU0_SB_CB<6>")
	)
	(segment
		(start 324.78091 -243.415566)
		(end 324.47103 -243.415566)
		(width 0.20066)
		(layer "F.Cu")
		(net "M_A_CPU0_SB_CB<6>")
	)
	(segment
		(start 323.75983 -242.884706)
		(end 323.55917 -243.085366)
		(width 0.20066)
		(layer "F.Cu")
		(net "M_A_CPU0_SB_CB<6>")
	)
	(segment
		(start 310.736996 -240.483898)
		(end 311.196482 -240.483898)
		(width 0.20066)
		(layer "F.Cu")
		(net "M_A_CPU0_SB_CB<6>")
	)
	(segment
		(start 325.89343 -243.415566)
		(end 325.69277 -243.214906)
		(width 0.20066)
		(layer "F.Cu")
		(net "M_A_CPU0_SB_CB<6>")
	)
	(segment
		(start 326.40397 -243.085366)
		(end 326.40397 -243.214906)
		(width 0.20066)
		(layer "F.Cu")
		(net "M_A_CPU0_SB_CB<6>")
	)
	(segment
		(start 327.82637 -243.085366)
		(end 327.82637 -243.214906)
		(width 0.20066)
		(layer "F.Cu")
		(net "M_A_CPU0_SB_CB<6>")
	)
	(segment
		(start 333.384652 -241.635026)
		(end 333.078582 -241.527584)
		(width 0.088646)
		(layer "F.Cu")
		(net "M_A_CPU0_SB_CB<6>")
	)
	(segment
		(start 310.153558 -241.09172)
		(end 310.52008 -241.09172)
		(width 0.20066)
		(layer "F.Cu")
		(net "M_A_CPU0_SB_CB<6>")
	)
	(segment
		(start 326.91451 -242.884706)
		(end 326.60463 -242.884706)
		(width 0.20066)
		(layer "F.Cu")
		(net "M_A_CPU0_SB_CB<6>")
	)
	(segment
		(start 333.658972 -241.34318)
		(end 333.568294 -241.433858)
		(width 0.088646)
		(layer "F.Cu")
		(net "M_A_CPU0_SB_CB<6>")
	)
	(segment
		(start 307.744368 -241.092482)
		(end 307.74513 -241.09172)
		(width 0.101854)
		(layer "F.Cu")
		(net "M_A_CPU0_SB_CB<6>")
	)
	(segment
		(start 311.379362 -240.666778)
		(end 312.987182 -240.666778)
		(width 0.20066)
		(layer "F.Cu")
		(net "M_A_CPU0_SB_CB<6>")
	)
	(segment
		(start 328.73823 -243.415566)
		(end 328.53757 -243.214906)
		(width 0.20066)
		(layer "F.Cu")
		(net "M_A_CPU0_SB_CB<6>")
	)
	(segment
		(start 331.32776 -241.438938)
		(end 331.279754 -241.486944)
		(width 0.088646)
		(layer "F.Cu")
		(net "M_A_CPU0_SB_CB<6>")
	)
	(segment
		(start 307.170328 -240.666778)
		(end 307.596032 -241.092482)
		(width 0.20066)
		(layer "F.Cu")
		(net "M_A_CPU0_SB_CB<6>")
	)
	(segment
		(start 327.82637 -243.214906)
		(end 327.62571 -243.415566)
		(width 0.20066)
		(layer "F.Cu")
		(net "M_A_CPU0_SB_CB<6>")
	)
	(segment
		(start 329.632564 -243.135658)
		(end 329.352656 -243.415566)
		(width 0.20066)
		(layer "F.Cu")
		(net "M_A_CPU0_SB_CB<6>")
	)
	(segment
		(start 319.094612 -241.120422)
		(end 315.23051 -241.120422)
		(width 0.20066)
		(layer "F.Cu")
		(net "M_A_CPU0_SB_CB<6>")
	)
	(segment
		(start 329.89774 -242.870482)
		(end 329.632564 -243.135658)
		(width 0.1016)
		(layer "F.Cu")
		(net "M_A_CPU0_SB_CB<6>")
	)
	(segment
		(start 326.60463 -242.884706)
		(end 326.40397 -243.085366)
		(width 0.20066)
		(layer "F.Cu")
		(net "M_A_CPU0_SB_CB<6>")
	)
	(segment
		(start 324.27037 -243.085366)
		(end 324.06971 -242.884706)
		(width 0.20066)
		(layer "F.Cu")
		(net "M_A_CPU0_SB_CB<6>")
	)
	(segment
		(start 329.352656 -243.415566)
		(end 328.73823 -243.415566)
		(width 0.20066)
		(layer "F.Cu")
		(net "M_A_CPU0_SB_CB<6>")
	)
	(segment
		(start 310.52008 -241.09172)
		(end 310.609996 -241.001804)
		(width 0.20066)
		(layer "F.Cu")
		(net "M_A_CPU0_SB_CB<6>")
	)
	(segment
		(start 328.33691 -242.884706)
		(end 328.02703 -242.884706)
		(width 0.20066)
		(layer "F.Cu")
		(net "M_A_CPU0_SB_CB<6>")
	)
	(segment
		(start 325.49211 -242.884706)
		(end 325.18223 -242.884706)
		(width 0.20066)
		(layer "F.Cu")
		(net "M_A_CPU0_SB_CB<6>")
	)
	(segment
		(start 315.23051 -241.120422)
		(end 314.617354 -240.507266)
		(width 0.20066)
		(layer "F.Cu")
		(net "M_A_CPU0_SB_CB<6>")
	)
	(segment
		(start 328.53757 -243.085366)
		(end 328.33691 -242.884706)
		(width 0.20066)
		(layer "F.Cu")
		(net "M_A_CPU0_SB_CB<6>")
	)
	(segment
		(start 327.11517 -243.085366)
		(end 326.91451 -242.884706)
		(width 0.20066)
		(layer "F.Cu")
		(net "M_A_CPU0_SB_CB<6>")
	)
	(segment
		(start 332.81874 -241.438938)
		(end 331.32776 -241.438938)
		(width 0.088646)
		(layer "F.Cu")
		(net "M_A_CPU0_SB_CB<6>")
	)
	(segment
		(start 327.11517 -243.214906)
		(end 327.11517 -243.085366)
		(width 0.20066)
		(layer "F.Cu")
		(net "M_A_CPU0_SB_CB<6>")
	)
	(segment
		(start 307.632862 -241.092482)
		(end 307.744368 -241.092482)
		(width 0.101854)
		(layer "F.Cu")
		(net "M_A_CPU0_SB_CB<6>")
	)
	(segment
		(start 324.06971 -242.884706)
		(end 323.75983 -242.884706)
		(width 0.20066)
		(layer "F.Cu")
		(net "M_A_CPU0_SB_CB<6>")
	)
	(segment
		(start 324.47103 -243.415566)
		(end 324.27037 -243.214906)
		(width 0.20066)
		(layer "F.Cu")
		(net "M_A_CPU0_SB_CB<6>")
	)
	(segment
		(start 323.55917 -243.085366)
		(end 323.55917 -243.214906)
		(width 0.20066)
		(layer "F.Cu")
		(net "M_A_CPU0_SB_CB<6>")
	)
	(segment
		(start 321.55384 -242.138962)
		(end 319.094612 -241.120422)
		(width 0.20066)
		(layer "F.Cu")
		(net "M_A_CPU0_SB_CB<6>")
	)
	(segment
		(start 333.479394 -241.635026)
		(end 333.384652 -241.635026)
		(width 0.088646)
		(layer "F.Cu")
		(net "M_A_CPU0_SB_CB<6>")
	)
	(segment
		(start 325.18223 -242.884706)
		(end 324.98157 -243.085366)
		(width 0.20066)
		(layer "F.Cu")
		(net "M_A_CPU0_SB_CB<6>")
	)
	(segment
		(start 334.018382 -241.744754)
		(end 333.898494 -241.624866)
		(width 0.088646)
		(layer "F.Cu")
		(net "M_A_CPU0_SB_CB<6>")
	)
	(segment
		(start 333.898494 -241.624866)
		(end 333.898494 -241.43208)
		(width 0.088646)
		(layer "F.Cu")
		(net "M_A_CPU0_SB_CB<6>")
	)
	(segment
		(start 332.83271 -241.452908)
		(end 332.81874 -241.438938)
		(width 0.088646)
		(layer "F.Cu")
		(net "M_A_CPU0_SB_CB<6>")
	)
	(segment
		(start 327.31583 -243.415566)
		(end 327.11517 -243.214906)
		(width 0.20066)
		(layer "F.Cu")
		(net "M_A_CPU0_SB_CB<6>")
	)
	(segment
		(start 307.74513 -241.09172)
		(end 310.01208 -241.09172)
		(width 0.1016)
		(layer "F.Cu")
		(net "M_A_CPU0_SB_CB<6>")
	)
	(segment
		(start 307.596032 -241.092482)
		(end 307.632862 -241.092482)
		(width 0.20066)
		(layer "F.Cu")
		(net "M_A_CPU0_SB_CB<6>")
	)
	(segment
		(start 324.27037 -243.214906)
		(end 324.27037 -243.085366)
		(width 0.20066)
		(layer "F.Cu")
		(net "M_A_CPU0_SB_CB<6>")
	)
	(arc
		(start 333.078582 -241.527584)
		(mid 332.958963 -241.479324)
		(end 332.83271 -241.452908)
		(width 0.088646)
		(layer "F.Cu")
		(net "M_A_CPU0_SB_CB<6>")
	)
	(segment
		(start 304.133758 -239.391698)
		(end 304.550826 -239.391698)
		(width 0.101854)
		(layer "F.Cu")
		(net "M_A_CPU0_SB_CB<5>")
	)
	(segment
		(start 301.343314 -239.81664)
		(end 302.653446 -239.81664)
		(width 0.20066)
		(layer "F.Cu")
		(net "M_A_CPU0_SB_CB<5>")
	)
	(segment
		(start 331.217016 -241.118136)
		(end 331.063854 -241.271298)
		(width 0.088646)
		(layer "F.Cu")
		(net "M_A_CPU0_SB_CB<5>")
	)
	(segment
		(start 314.523374 -239.391698)
		(end 314.248292 -239.391698)
		(width 0.20066)
		(layer "F.Cu")
		(net "M_A_CPU0_SB_CB<5>")
	)
	(segment
		(start 311.473596 -239.391698)
		(end 310.846978 -240.018316)
		(width 0.20066)
		(layer "F.Cu")
		(net "M_A_CPU0_SB_CB<5>")
	)
	(segment
		(start 306.730908 -239.391698)
		(end 306.810664 -239.391698)
		(width 0.20066)
		(layer "F.Cu")
		(net "M_A_CPU0_SB_CB<5>")
	)
	(segment
		(start 332.038452 -241.118136)
		(end 331.217016 -241.118136)
		(width 0.088646)
		(layer "F.Cu")
		(net "M_A_CPU0_SB_CB<5>")
	)
	(segment
		(start 307.235606 -239.81664)
		(end 308.887114 -239.81664)
		(width 0.20066)
		(layer "F.Cu")
		(net "M_A_CPU0_SB_CB<5>")
	)
	(segment
		(start 311.925462 -239.391698)
		(end 311.747662 -239.391698)
		(width 0.101854)
		(layer "F.Cu")
		(net "M_A_CPU0_SB_CB<5>")
	)
	(segment
		(start 322.052696 -241.597942)
		(end 318.958468 -240.316004)
		(width 0.20066)
		(layer "F.Cu")
		(net "M_A_CPU0_SB_CB<5>")
	)
	(segment
		(start 311.747662 -239.391698)
		(end 311.473596 -239.391698)
		(width 0.20066)
		(layer "F.Cu")
		(net "M_A_CPU0_SB_CB<5>")
	)
	(segment
		(start 332.132686 -241.21237)
		(end 332.038452 -241.118136)
		(width 0.088646)
		(layer "F.Cu")
		(net "M_A_CPU0_SB_CB<5>")
	)
	(segment
		(start 303.523396 -239.917478)
		(end 303.523396 -239.604042)
		(width 0.20066)
		(layer "F.Cu")
		(net "M_A_CPU0_SB_CB<5>")
	)
	(segment
		(start 322.68414 -242.229386)
		(end 322.052696 -241.597942)
		(width 0.20066)
		(layer "F.Cu")
		(net "M_A_CPU0_SB_CB<5>")
	)
	(segment
		(start 310.846978 -240.018316)
		(end 310.400446 -240.018316)
		(width 0.20066)
		(layer "F.Cu")
		(net "M_A_CPU0_SB_CB<5>")
	)
	(segment
		(start 314.248292 -239.391698)
		(end 313.843416 -239.391698)
		(width 0.101854)
		(layer "F.Cu")
		(net "M_A_CPU0_SB_CB<5>")
	)
	(segment
		(start 313.843416 -239.391698)
		(end 311.925462 -239.391698)
		(width 0.1016)
		(layer "F.Cu")
		(net "M_A_CPU0_SB_CB<5>")
	)
	(segment
		(start 314.732416 -239.60074)
		(end 314.523374 -239.391698)
		(width 0.20066)
		(layer "F.Cu")
		(net "M_A_CPU0_SB_CB<5>")
	)
	(segment
		(start 318.958468 -240.316004)
		(end 315.333888 -240.316004)
		(width 0.20066)
		(layer "F.Cu")
		(net "M_A_CPU0_SB_CB<5>")
	)
	(segment
		(start 303.523396 -239.604042)
		(end 303.73574 -239.391698)
		(width 0.20066)
		(layer "F.Cu")
		(net "M_A_CPU0_SB_CB<5>")
	)
	(segment
		(start 333.26578 -241.203226)
		(end 332.318614 -241.21237)
		(width 0.088646)
		(layer "F.Cu")
		(net "M_A_CPU0_SB_CB<5>")
	)
	(segment
		(start 310.19877 -239.81664)
		(end 308.887114 -239.81664)
		(width 0.20066)
		(layer "F.Cu")
		(net "M_A_CPU0_SB_CB<5>")
	)
	(segment
		(start 304.550826 -239.391698)
		(end 306.289202 -239.391698)
		(width 0.1016)
		(layer "F.Cu")
		(net "M_A_CPU0_SB_CB<5>")
	)
	(segment
		(start 302.955198 -240.118392)
		(end 303.322482 -240.118392)
		(width 0.20066)
		(layer "F.Cu")
		(net "M_A_CPU0_SB_CB<5>")
	)
	(segment
		(start 303.322482 -240.118392)
		(end 303.523396 -239.917478)
		(width 0.20066)
		(layer "F.Cu")
		(net "M_A_CPU0_SB_CB<5>")
	)
	(segment
		(start 310.400446 -240.018316)
		(end 310.19877 -239.81664)
		(width 0.20066)
		(layer "F.Cu")
		(net "M_A_CPU0_SB_CB<5>")
	)
	(segment
		(start 331.063854 -241.271298)
		(end 330.105766 -242.229386)
		(width 0.101854)
		(layer "F.Cu")
		(net "M_A_CPU0_SB_CB<5>")
	)
	(segment
		(start 330.105766 -242.229386)
		(end 329.632564 -242.229386)
		(width 0.1016)
		(layer "F.Cu")
		(net "M_A_CPU0_SB_CB<5>")
	)
	(segment
		(start 329.632564 -242.229386)
		(end 322.68414 -242.229386)
		(width 0.20066)
		(layer "F.Cu")
		(net "M_A_CPU0_SB_CB<5>")
	)
	(segment
		(start 315.333888 -240.316004)
		(end 314.732416 -239.714532)
		(width 0.20066)
		(layer "F.Cu")
		(net "M_A_CPU0_SB_CB<5>")
	)
	(segment
		(start 303.73574 -239.391698)
		(end 304.133758 -239.391698)
		(width 0.20066)
		(layer "F.Cu")
		(net "M_A_CPU0_SB_CB<5>")
	)
	(segment
		(start 306.289202 -239.391698)
		(end 306.730908 -239.391698)
		(width 0.101854)
		(layer "F.Cu")
		(net "M_A_CPU0_SB_CB<5>")
	)
	(segment
		(start 306.810664 -239.391698)
		(end 307.235606 -239.81664)
		(width 0.20066)
		(layer "F.Cu")
		(net "M_A_CPU0_SB_CB<5>")
	)
	(segment
		(start 302.653446 -239.81664)
		(end 302.955198 -240.118392)
		(width 0.20066)
		(layer "F.Cu")
		(net "M_A_CPU0_SB_CB<5>")
	)
	(segment
		(start 332.318614 -241.21237)
		(end 332.132686 -241.21237)
		(width 0.088646)
		(layer "F.Cu")
		(net "M_A_CPU0_SB_CB<5>")
	)
	(segment
		(start 314.732416 -239.714532)
		(end 314.732416 -239.60074)
		(width 0.20066)
		(layer "F.Cu")
		(net "M_A_CPU0_SB_CB<5>")
	)
	(segment
		(start 304.550826 -241.09172)
		(end 306.289202 -241.09172)
		(width 0.1016)
		(layer "F.Cu")
		(net "M_A_CPU0_SB_CB<4>")
	)
	(segment
		(start 311.192164 -241.09172)
		(end 310.767222 -241.516662)
		(width 0.20066)
		(layer "F.Cu")
		(net "M_A_CPU0_SB_CB<4>")
	)
	(segment
		(start 306.848002 -241.09172)
		(end 307.327046 -241.570764)
		(width 0.20066)
		(layer "F.Cu")
		(net "M_A_CPU0_SB_CB<4>")
	)
	(segment
		(start 322.462906 -244.055138)
		(end 321.041776 -242.634008)
		(width 0.20066)
		(layer "F.Cu")
		(net "M_A_CPU0_SB_CB<4>")
	)
	(segment
		(start 314.244228 -241.09172)
		(end 314.104528 -241.09172)
		(width 0.101854)
		(layer "F.Cu")
		(net "M_A_CPU0_SB_CB<4>")
	)
	(segment
		(start 329.632564 -244.055138)
		(end 322.462906 -244.055138)
		(width 0.20066)
		(layer "F.Cu")
		(net "M_A_CPU0_SB_CB<4>")
	)
	(segment
		(start 331.518006 -241.680238)
		(end 331.4573 -241.740944)
		(width 0.088646)
		(layer "F.Cu")
		(net "M_A_CPU0_SB_CB<4>")
	)
	(segment
		(start 319.07226 -241.817906)
		(end 315.013086 -241.817906)
		(width 0.20066)
		(layer "F.Cu")
		(net "M_A_CPU0_SB_CB<4>")
	)
	(segment
		(start 310.767222 -241.516662)
		(end 308.887114 -241.516662)
		(width 0.20066)
		(layer "F.Cu")
		(net "M_A_CPU0_SB_CB<4>")
	)
	(segment
		(start 321.041776 -242.634008)
		(end 319.07226 -241.817906)
		(width 0.20066)
		(layer "F.Cu")
		(net "M_A_CPU0_SB_CB<4>")
	)
	(segment
		(start 312.12536 -241.09172)
		(end 311.735724 -241.09172)
		(width 0.101854)
		(layer "F.Cu")
		(net "M_A_CPU0_SB_CB<4>")
	)
	(segment
		(start 302.653446 -241.516662)
		(end 302.953674 -241.81689)
		(width 0.20066)
		(layer "F.Cu")
		(net "M_A_CPU0_SB_CB<4>")
	)
	(segment
		(start 315.013086 -241.817906)
		(end 314.2869 -241.09172)
		(width 0.20066)
		(layer "F.Cu")
		(net "M_A_CPU0_SB_CB<4>")
	)
	(segment
		(start 301.343314 -241.516662)
		(end 302.653446 -241.516662)
		(width 0.20066)
		(layer "F.Cu")
		(net "M_A_CPU0_SB_CB<4>")
	)
	(segment
		(start 330.130912 -243.067332)
		(end 330.130912 -243.772436)
		(width 0.1016)
		(layer "F.Cu")
		(net "M_A_CPU0_SB_CB<4>")
	)
	(segment
		(start 331.4573 -241.740944)
		(end 330.130912 -243.067332)
		(width 0.1016)
		(layer "F.Cu")
		(net "M_A_CPU0_SB_CB<4>")
	)
	(segment
		(start 302.953674 -241.81689)
		(end 303.322482 -241.81689)
		(width 0.20066)
		(layer "F.Cu")
		(net "M_A_CPU0_SB_CB<4>")
	)
	(segment
		(start 304.185828 -241.09172)
		(end 304.550826 -241.09172)
		(width 0.101854)
		(layer "F.Cu")
		(net "M_A_CPU0_SB_CB<4>")
	)
	(segment
		(start 329.84821 -244.055138)
		(end 329.632564 -244.055138)
		(width 0.1016)
		(layer "F.Cu")
		(net "M_A_CPU0_SB_CB<4>")
	)
	(segment
		(start 303.523396 -241.260122)
		(end 303.691798 -241.09172)
		(width 0.20066)
		(layer "F.Cu")
		(net "M_A_CPU0_SB_CB<4>")
	)
	(segment
		(start 306.72659 -241.09172)
		(end 306.848002 -241.09172)
		(width 0.20066)
		(layer "F.Cu")
		(net "M_A_CPU0_SB_CB<4>")
	)
	(segment
		(start 311.735724 -241.09172)
		(end 311.192164 -241.09172)
		(width 0.20066)
		(layer "F.Cu")
		(net "M_A_CPU0_SB_CB<4>")
	)
	(segment
		(start 330.130912 -243.772436)
		(end 329.84821 -244.055138)
		(width 0.1016)
		(layer "F.Cu")
		(net "M_A_CPU0_SB_CB<4>")
	)
	(segment
		(start 303.691798 -241.09172)
		(end 304.185828 -241.09172)
		(width 0.20066)
		(layer "F.Cu")
		(net "M_A_CPU0_SB_CB<4>")
	)
	(segment
		(start 314.2869 -241.09172)
		(end 314.244228 -241.09172)
		(width 0.20066)
		(layer "F.Cu")
		(net "M_A_CPU0_SB_CB<4>")
	)
	(segment
		(start 306.289202 -241.09172)
		(end 306.72659 -241.09172)
		(width 0.101854)
		(layer "F.Cu")
		(net "M_A_CPU0_SB_CB<4>")
	)
	(segment
		(start 303.322482 -241.81689)
		(end 303.523396 -241.615976)
		(width 0.20066)
		(layer "F.Cu")
		(net "M_A_CPU0_SB_CB<4>")
	)
	(segment
		(start 303.523396 -241.615976)
		(end 303.523396 -241.260122)
		(width 0.20066)
		(layer "F.Cu")
		(net "M_A_CPU0_SB_CB<4>")
	)
	(segment
		(start 308.833012 -241.570764)
		(end 308.887114 -241.516662)
		(width 0.20066)
		(layer "F.Cu")
		(net "M_A_CPU0_SB_CB<4>")
	)
	(segment
		(start 314.104528 -241.09172)
		(end 312.12536 -241.09172)
		(width 0.1016)
		(layer "F.Cu")
		(net "M_A_CPU0_SB_CB<4>")
	)
	(segment
		(start 333.375508 -241.920014)
		(end 333.026512 -241.717576)
		(width 0.088646)
		(layer "F.Cu")
		(net "M_A_CPU0_SB_CB<4>")
	)
	(segment
		(start 332.887066 -241.680238)
		(end 331.518006 -241.680238)
		(width 0.088646)
		(layer "F.Cu")
		(net "M_A_CPU0_SB_CB<4>")
	)
	(segment
		(start 307.327046 -241.570764)
		(end 308.833012 -241.570764)
		(width 0.20066)
		(layer "F.Cu")
		(net "M_A_CPU0_SB_CB<4>")
	)
	(arc
		(start 333.735934 -242.017042)
		(mid 333.54932 -241.992318)
		(end 333.375508 -241.920014)
		(width 0.088646)
		(layer "F.Cu")
		(net "M_A_CPU0_SB_CB<4>")
	)
	(arc
		(start 333.026512 -241.717576)
		(mid 332.959248 -241.689717)
		(end 332.887066 -241.680238)
		(width 0.088646)
		(layer "F.Cu")
		(net "M_A_CPU0_SB_CB<4>")
	)
	(segment
		(start 334.365092 -238.761524)
		(end 334.675734 -238.761524)
		(width 0.088646)
		(layer "F.Cu")
		(net "M_A_CPU0_SB_CB<3>")
	)
	(segment
		(start 327.038462 -235.921804)
		(end 327.239122 -235.721144)
		(width 0.20066)
		(layer "F.Cu")
		(net "M_A_CPU0_SB_CB<3>")
	)
	(segment
		(start 307.0479 -232.955846)
		(end 307.533802 -233.441748)
		(width 0.20066)
		(layer "F.Cu")
		(net "M_A_CPU0_SB_CB<3>")
	)
	(segment
		(start 312.987182 -233.016806)
		(end 314.271406 -233.016806)
		(width 0.20066)
		(layer "F.Cu")
		(net "M_A_CPU0_SB_CB<3>")
	)
	(segment
		(start 328.82967 -236.801406)
		(end 329.82408 -237.795816)
		(width 0.1016)
		(layer "F.Cu")
		(net "M_A_CPU0_SB_CB<3>")
	)
	(segment
		(start 332.687422 -237.899448)
		(end 333.000604 -238.21263)
		(width 0.088646)
		(layer "F.Cu")
		(net "M_A_CPU0_SB_CB<3>")
	)
	(segment
		(start 328.327512 -236.286802)
		(end 328.519282 -236.286802)
		(width 0.1016)
		(layer "F.Cu")
		(net "M_A_CPU0_SB_CB<3>")
	)
	(segment
		(start 328.82967 -236.59719)
		(end 328.82967 -236.801406)
		(width 0.1016)
		(layer "F.Cu")
		(net "M_A_CPU0_SB_CB<3>")
	)
	(segment
		(start 306.318158 -233.016806)
		(end 306.379118 -232.955846)
		(width 0.20066)
		(layer "F.Cu")
		(net "M_A_CPU0_SB_CB<3>")
	)
	(segment
		(start 325.995538 -235.607352)
		(end 325.995538 -235.890816)
		(width 0.20066)
		(layer "F.Cu")
		(net "M_A_CPU0_SB_CB<3>")
	)
	(segment
		(start 310.01208 -233.441748)
		(end 310.146954 -233.441748)
		(width 0.101854)
		(layer "F.Cu")
		(net "M_A_CPU0_SB_CB<3>")
	)
	(segment
		(start 334.297274 -238.693706)
		(end 334.365092 -238.761524)
		(width 0.088646)
		(layer "F.Cu")
		(net "M_A_CPU0_SB_CB<3>")
	)
	(segment
		(start 310.482742 -233.441748)
		(end 310.609996 -233.314494)
		(width 0.20066)
		(layer "F.Cu")
		(net "M_A_CPU0_SB_CB<3>")
	)
	(segment
		(start 307.63845 -233.441748)
		(end 307.82768 -233.441748)
		(width 0.101854)
		(layer "F.Cu")
		(net "M_A_CPU0_SB_CB<3>")
	)
	(segment
		(start 325.828914 -234.76839)
		(end 326.112378 -234.76839)
		(width 0.20066)
		(layer "F.Cu")
		(net "M_A_CPU0_SB_CB<3>")
	)
	(segment
		(start 311.599834 -233.016806)
		(end 312.987182 -233.016806)
		(width 0.20066)
		(layer "F.Cu")
		(net "M_A_CPU0_SB_CB<3>")
	)
	(segment
		(start 331.678026 -237.795816)
		(end 331.781658 -237.899448)
		(width 0.1016)
		(layer "F.Cu")
		(net "M_A_CPU0_SB_CB<3>")
	)
	(segment
		(start 315.167518 -232.735374)
		(end 316.430914 -233.99877)
		(width 0.20066)
		(layer "F.Cu")
		(net "M_A_CPU0_SB_CB<3>")
	)
	(segment
		(start 326.112378 -234.76839)
		(end 326.331834 -234.987846)
		(width 0.20066)
		(layer "F.Cu")
		(net "M_A_CPU0_SB_CB<3>")
	)
	(segment
		(start 327.239122 -235.721144)
		(end 327.549002 -235.721144)
		(width 0.20066)
		(layer "F.Cu")
		(net "M_A_CPU0_SB_CB<3>")
	)
	(segment
		(start 325.492618 -235.104432)
		(end 325.828914 -234.76839)
		(width 0.20066)
		(layer "F.Cu")
		(net "M_A_CPU0_SB_CB<3>")
	)
	(segment
		(start 310.146954 -233.441748)
		(end 310.482742 -233.441748)
		(width 0.20066)
		(layer "F.Cu")
		(net "M_A_CPU0_SB_CB<3>")
	)
	(segment
		(start 310.609996 -233.092498)
		(end 310.90743 -232.795064)
		(width 0.20066)
		(layer "F.Cu")
		(net "M_A_CPU0_SB_CB<3>")
	)
	(segment
		(start 305.443382 -233.016806)
		(end 306.318158 -233.016806)
		(width 0.20066)
		(layer "F.Cu")
		(net "M_A_CPU0_SB_CB<3>")
	)
	(segment
		(start 310.90743 -232.795064)
		(end 311.378092 -232.795064)
		(width 0.20066)
		(layer "F.Cu")
		(net "M_A_CPU0_SB_CB<3>")
	)
	(segment
		(start 327.749662 -235.921804)
		(end 327.749662 -236.086142)
		(width 0.20066)
		(layer "F.Cu")
		(net "M_A_CPU0_SB_CB<3>")
	)
	(segment
		(start 326.391524 -236.286802)
		(end 326.837802 -236.286802)
		(width 0.20066)
		(layer "F.Cu")
		(net "M_A_CPU0_SB_CB<3>")
	)
	(segment
		(start 327.549002 -235.721144)
		(end 327.749662 -235.921804)
		(width 0.20066)
		(layer "F.Cu")
		(net "M_A_CPU0_SB_CB<3>")
	)
	(segment
		(start 327.749662 -236.086142)
		(end 327.950322 -236.286802)
		(width 0.20066)
		(layer "F.Cu")
		(net "M_A_CPU0_SB_CB<3>")
	)
	(segment
		(start 307.82768 -233.441748)
		(end 310.01208 -233.441748)
		(width 0.1016)
		(layer "F.Cu")
		(net "M_A_CPU0_SB_CB<3>")
	)
	(segment
		(start 326.331834 -234.987846)
		(end 326.331834 -235.27131)
		(width 0.20066)
		(layer "F.Cu")
		(net "M_A_CPU0_SB_CB<3>")
	)
	(segment
		(start 326.331834 -235.27131)
		(end 325.995538 -235.607352)
		(width 0.20066)
		(layer "F.Cu")
		(net "M_A_CPU0_SB_CB<3>")
	)
	(segment
		(start 334.008222 -238.26597)
		(end 334.018636 -238.272066)
		(width 0.088646)
		(layer "F.Cu")
		(net "M_A_CPU0_SB_CB<3>")
	)
	(segment
		(start 325.209154 -235.104432)
		(end 325.492618 -235.104432)
		(width 0.20066)
		(layer "F.Cu")
		(net "M_A_CPU0_SB_CB<3>")
	)
	(segment
		(start 311.378092 -232.795064)
		(end 311.599834 -233.016806)
		(width 0.20066)
		(layer "F.Cu")
		(net "M_A_CPU0_SB_CB<3>")
	)
	(segment
		(start 325.995538 -235.890816)
		(end 326.391524 -236.286802)
		(width 0.20066)
		(layer "F.Cu")
		(net "M_A_CPU0_SB_CB<3>")
	)
	(segment
		(start 306.379118 -232.955846)
		(end 307.0479 -232.955846)
		(width 0.20066)
		(layer "F.Cu")
		(net "M_A_CPU0_SB_CB<3>")
	)
	(segment
		(start 314.552838 -232.735374)
		(end 315.167518 -232.735374)
		(width 0.20066)
		(layer "F.Cu")
		(net "M_A_CPU0_SB_CB<3>")
	)
	(segment
		(start 324.103492 -233.99877)
		(end 325.209154 -235.104432)
		(width 0.20066)
		(layer "F.Cu")
		(net "M_A_CPU0_SB_CB<3>")
	)
	(segment
		(start 316.430914 -233.99877)
		(end 324.103492 -233.99877)
		(width 0.20066)
		(layer "F.Cu")
		(net "M_A_CPU0_SB_CB<3>")
	)
	(segment
		(start 310.609996 -233.314494)
		(end 310.609996 -233.092498)
		(width 0.20066)
		(layer "F.Cu")
		(net "M_A_CPU0_SB_CB<3>")
	)
	(segment
		(start 328.519282 -236.286802)
		(end 328.82967 -236.59719)
		(width 0.1016)
		(layer "F.Cu")
		(net "M_A_CPU0_SB_CB<3>")
	)
	(segment
		(start 326.837802 -236.286802)
		(end 327.038462 -236.086142)
		(width 0.20066)
		(layer "F.Cu")
		(net "M_A_CPU0_SB_CB<3>")
	)
	(segment
		(start 327.950322 -236.286802)
		(end 328.327512 -236.286802)
		(width 0.20066)
		(layer "F.Cu")
		(net "M_A_CPU0_SB_CB<3>")
	)
	(segment
		(start 331.781658 -237.899448)
		(end 332.147164 -237.899448)
		(width 0.1016)
		(layer "F.Cu")
		(net "M_A_CPU0_SB_CB<3>")
	)
	(segment
		(start 332.147164 -237.899448)
		(end 332.687422 -237.899448)
		(width 0.088646)
		(layer "F.Cu")
		(net "M_A_CPU0_SB_CB<3>")
	)
	(segment
		(start 307.533802 -233.441748)
		(end 307.63845 -233.441748)
		(width 0.20066)
		(layer "F.Cu")
		(net "M_A_CPU0_SB_CB<3>")
	)
	(segment
		(start 327.038462 -236.086142)
		(end 327.038462 -235.921804)
		(width 0.20066)
		(layer "F.Cu")
		(net "M_A_CPU0_SB_CB<3>")
	)
	(segment
		(start 329.82408 -237.795816)
		(end 331.678026 -237.795816)
		(width 0.1016)
		(layer "F.Cu")
		(net "M_A_CPU0_SB_CB<3>")
	)
	(segment
		(start 314.271406 -233.016806)
		(end 314.552838 -232.735374)
		(width 0.20066)
		(layer "F.Cu")
		(net "M_A_CPU0_SB_CB<3>")
	)
	(arc
		(start 334.018636 -238.272066)
		(mid 334.207683 -238.450015)
		(end 334.297274 -238.693706)
		(width 0.088646)
		(layer "F.Cu")
		(net "M_A_CPU0_SB_CB<3>")
	)
	(arc
		(start 333.452978 -238.272066)
		(mid 333.729791 -238.196196)
		(end 334.008222 -238.26597)
		(width 0.088646)
		(layer "F.Cu")
		(net "M_A_CPU0_SB_CB<3>")
	)
	(arc
		(start 333.078582 -238.272066)
		(mid 333.26578 -238.322209)
		(end 333.452978 -238.272066)
		(width 0.088646)
		(layer "F.Cu")
		(net "M_A_CPU0_SB_CB<3>")
	)
	(arc
		(start 333.000604 -238.21263)
		(mid 333.037652 -238.244893)
		(end 333.078582 -238.272066)
		(width 0.088646)
		(layer "F.Cu")
		(net "M_A_CPU0_SB_CB<3>")
	)
	(segment
		(start 329.570842 -238.405416)
		(end 328.732134 -237.566708)
		(width 0.1016)
		(layer "F.Cu")
		(net "M_A_CPU0_SB_CB<2>")
	)
	(segment
		(start 319.73266 -235.640118)
		(end 319.73266 -235.737146)
		(width 0.20066)
		(layer "F.Cu")
		(net "M_A_CPU0_SB_CB<2>")
	)
	(segment
		(start 331.259688 -238.405416)
		(end 329.570842 -238.405416)
		(width 0.1016)
		(layer "F.Cu")
		(net "M_A_CPU0_SB_CB<2>")
	)
	(segment
		(start 320.64452 -235.937806)
		(end 320.44386 -235.737146)
		(width 0.20066)
		(layer "F.Cu")
		(net "M_A_CPU0_SB_CB<2>")
	)
	(segment
		(start 320.2432 -235.439458)
		(end 319.93332 -235.439458)
		(width 0.20066)
		(layer "F.Cu")
		(net "M_A_CPU0_SB_CB<2>")
	)
	(segment
		(start 322.3768 -235.937806)
		(end 322.06692 -235.937806)
		(width 0.20066)
		(layer "F.Cu")
		(net "M_A_CPU0_SB_CB<2>")
	)
	(segment
		(start 321.6656 -235.439458)
		(end 321.35572 -235.439458)
		(width 0.20066)
		(layer "F.Cu")
		(net "M_A_CPU0_SB_CB<2>")
	)
	(segment
		(start 311.26938 -234.494832)
		(end 311.491122 -234.716574)
		(width 0.20066)
		(layer "F.Cu")
		(net "M_A_CPU0_SB_CB<2>")
	)
	(segment
		(start 321.35572 -235.439458)
		(end 321.15506 -235.640118)
		(width 0.20066)
		(layer "F.Cu")
		(net "M_A_CPU0_SB_CB<2>")
	)
	(segment
		(start 321.86626 -235.640118)
		(end 321.6656 -235.439458)
		(width 0.20066)
		(layer "F.Cu")
		(net "M_A_CPU0_SB_CB<2>")
	)
	(segment
		(start 332.736952 -239.421162)
		(end 332.136242 -239.421162)
		(width 0.088646)
		(layer "F.Cu")
		(net "M_A_CPU0_SB_CB<2>")
	)
	(segment
		(start 318.51092 -235.439458)
		(end 318.31026 -235.640118)
		(width 0.20066)
		(layer "F.Cu")
		(net "M_A_CPU0_SB_CB<2>")
	)
	(segment
		(start 317.3984 -235.439458)
		(end 315.92647 -235.439458)
		(width 0.20066)
		(layer "F.Cu")
		(net "M_A_CPU0_SB_CB<2>")
	)
	(segment
		(start 319.73266 -235.737146)
		(end 319.532 -235.937806)
		(width 0.20066)
		(layer "F.Cu")
		(net "M_A_CPU0_SB_CB<2>")
	)
	(segment
		(start 305.443382 -234.716574)
		(end 307.122576 -234.716574)
		(width 0.20066)
		(layer "F.Cu")
		(net "M_A_CPU0_SB_CB<2>")
	)
	(segment
		(start 325.675752 -237.566708)
		(end 323.548502 -235.439458)
		(width 0.20066)
		(layer "F.Cu")
		(net "M_A_CPU0_SB_CB<2>")
	)
	(segment
		(start 307.122576 -234.716574)
		(end 307.547518 -235.141516)
		(width 0.20066)
		(layer "F.Cu")
		(net "M_A_CPU0_SB_CB<2>")
	)
	(segment
		(start 321.15506 -235.640118)
		(end 321.15506 -235.737146)
		(width 0.20066)
		(layer "F.Cu")
		(net "M_A_CPU0_SB_CB<2>")
	)
	(segment
		(start 307.547518 -235.141516)
		(end 307.62448 -235.141516)
		(width 0.20066)
		(layer "F.Cu")
		(net "M_A_CPU0_SB_CB<2>")
	)
	(segment
		(start 314.613036 -234.453176)
		(end 314.349638 -234.716574)
		(width 0.20066)
		(layer "F.Cu")
		(net "M_A_CPU0_SB_CB<2>")
	)
	(segment
		(start 310.609996 -235.014262)
		(end 310.609996 -234.660694)
		(width 0.20066)
		(layer "F.Cu")
		(net "M_A_CPU0_SB_CB<2>")
	)
	(segment
		(start 319.02146 -235.640118)
		(end 318.8208 -235.439458)
		(width 0.20066)
		(layer "F.Cu")
		(net "M_A_CPU0_SB_CB<2>")
	)
	(segment
		(start 318.31026 -235.640118)
		(end 318.31026 -235.737146)
		(width 0.20066)
		(layer "F.Cu")
		(net "M_A_CPU0_SB_CB<2>")
	)
	(segment
		(start 328.732134 -237.566708)
		(end 328.495152 -237.566708)
		(width 0.1016)
		(layer "F.Cu")
		(net "M_A_CPU0_SB_CB<2>")
	)
	(segment
		(start 310.775858 -234.494832)
		(end 311.26938 -234.494832)
		(width 0.20066)
		(layer "F.Cu")
		(net "M_A_CPU0_SB_CB<2>")
	)
	(segment
		(start 321.15506 -235.737146)
		(end 320.9544 -235.937806)
		(width 0.20066)
		(layer "F.Cu")
		(net "M_A_CPU0_SB_CB<2>")
	)
	(segment
		(start 319.93332 -235.439458)
		(end 319.73266 -235.640118)
		(width 0.20066)
		(layer "F.Cu")
		(net "M_A_CPU0_SB_CB<2>")
	)
	(segment
		(start 318.31026 -235.737146)
		(end 318.1096 -235.937806)
		(width 0.20066)
		(layer "F.Cu")
		(net "M_A_CPU0_SB_CB<2>")
	)
	(segment
		(start 315.92647 -235.439458)
		(end 314.940188 -234.453176)
		(width 0.20066)
		(layer "F.Cu")
		(net "M_A_CPU0_SB_CB<2>")
	)
	(segment
		(start 319.532 -235.937806)
		(end 319.22212 -235.937806)
		(width 0.20066)
		(layer "F.Cu")
		(net "M_A_CPU0_SB_CB<2>")
	)
	(segment
		(start 310.609996 -234.660694)
		(end 310.775858 -234.494832)
		(width 0.20066)
		(layer "F.Cu")
		(net "M_A_CPU0_SB_CB<2>")
	)
	(segment
		(start 317.59906 -235.737146)
		(end 317.59906 -235.640118)
		(width 0.20066)
		(layer "F.Cu")
		(net "M_A_CPU0_SB_CB<2>")
	)
	(segment
		(start 320.9544 -235.937806)
		(end 320.64452 -235.937806)
		(width 0.20066)
		(layer "F.Cu")
		(net "M_A_CPU0_SB_CB<2>")
	)
	(segment
		(start 318.1096 -235.937806)
		(end 317.79972 -235.937806)
		(width 0.20066)
		(layer "F.Cu")
		(net "M_A_CPU0_SB_CB<2>")
	)
	(segment
		(start 321.86626 -235.737146)
		(end 321.86626 -235.640118)
		(width 0.20066)
		(layer "F.Cu")
		(net "M_A_CPU0_SB_CB<2>")
	)
	(segment
		(start 320.44386 -235.737146)
		(end 320.44386 -235.640118)
		(width 0.20066)
		(layer "F.Cu")
		(net "M_A_CPU0_SB_CB<2>")
	)
	(segment
		(start 314.940188 -234.453176)
		(end 314.613036 -234.453176)
		(width 0.20066)
		(layer "F.Cu")
		(net "M_A_CPU0_SB_CB<2>")
	)
	(segment
		(start 319.02146 -235.737146)
		(end 319.02146 -235.640118)
		(width 0.20066)
		(layer "F.Cu")
		(net "M_A_CPU0_SB_CB<2>")
	)
	(segment
		(start 310.482742 -235.141516)
		(end 310.609996 -235.014262)
		(width 0.20066)
		(layer "F.Cu")
		(net "M_A_CPU0_SB_CB<2>")
	)
	(segment
		(start 322.77812 -235.439458)
		(end 322.57746 -235.640118)
		(width 0.20066)
		(layer "F.Cu")
		(net "M_A_CPU0_SB_CB<2>")
	)
	(segment
		(start 322.06692 -235.937806)
		(end 321.86626 -235.737146)
		(width 0.20066)
		(layer "F.Cu")
		(net "M_A_CPU0_SB_CB<2>")
	)
	(segment
		(start 332.016862 -239.301782)
		(end 331.91831 -239.064038)
		(width 0.088646)
		(layer "F.Cu")
		(net "M_A_CPU0_SB_CB<2>")
	)
	(segment
		(start 307.62448 -235.141516)
		(end 307.85308 -235.141516)
		(width 0.101854)
		(layer "F.Cu")
		(net "M_A_CPU0_SB_CB<2>")
	)
	(segment
		(start 307.85308 -235.141516)
		(end 310.01208 -235.141516)
		(width 0.1016)
		(layer "F.Cu")
		(net "M_A_CPU0_SB_CB<2>")
	)
	(segment
		(start 314.349638 -234.716574)
		(end 312.987182 -234.716574)
		(width 0.20066)
		(layer "F.Cu")
		(net "M_A_CPU0_SB_CB<2>")
	)
	(segment
		(start 317.59906 -235.640118)
		(end 317.3984 -235.439458)
		(width 0.20066)
		(layer "F.Cu")
		(net "M_A_CPU0_SB_CB<2>")
	)
	(segment
		(start 310.153304 -235.141516)
		(end 310.482742 -235.141516)
		(width 0.20066)
		(layer "F.Cu")
		(net "M_A_CPU0_SB_CB<2>")
	)
	(segment
		(start 332.912212 -239.245902)
		(end 332.736952 -239.421162)
		(width 0.088646)
		(layer "F.Cu")
		(net "M_A_CPU0_SB_CB<2>")
	)
	(segment
		(start 320.44386 -235.640118)
		(end 320.2432 -235.439458)
		(width 0.20066)
		(layer "F.Cu")
		(net "M_A_CPU0_SB_CB<2>")
	)
	(segment
		(start 335.14538 -239.57534)
		(end 334.440784 -239.168432)
		(width 0.088646)
		(layer "F.Cu")
		(net "M_A_CPU0_SB_CB<2>")
	)
	(segment
		(start 317.79972 -235.937806)
		(end 317.59906 -235.737146)
		(width 0.20066)
		(layer "F.Cu")
		(net "M_A_CPU0_SB_CB<2>")
	)
	(segment
		(start 322.57746 -235.737146)
		(end 322.3768 -235.937806)
		(width 0.20066)
		(layer "F.Cu")
		(net "M_A_CPU0_SB_CB<2>")
	)
	(segment
		(start 332.136242 -239.421162)
		(end 332.016862 -239.301782)
		(width 0.088646)
		(layer "F.Cu")
		(net "M_A_CPU0_SB_CB<2>")
	)
	(segment
		(start 311.491122 -234.716574)
		(end 312.987182 -234.716574)
		(width 0.20066)
		(layer "F.Cu")
		(net "M_A_CPU0_SB_CB<2>")
	)
	(segment
		(start 331.836522 -238.98225)
		(end 331.259688 -238.405416)
		(width 0.101854)
		(layer "F.Cu")
		(net "M_A_CPU0_SB_CB<2>")
	)
	(segment
		(start 323.548502 -235.439458)
		(end 322.77812 -235.439458)
		(width 0.20066)
		(layer "F.Cu")
		(net "M_A_CPU0_SB_CB<2>")
	)
	(segment
		(start 328.495152 -237.566708)
		(end 325.675752 -237.566708)
		(width 0.20066)
		(layer "F.Cu")
		(net "M_A_CPU0_SB_CB<2>")
	)
	(segment
		(start 322.57746 -235.640118)
		(end 322.57746 -235.737146)
		(width 0.20066)
		(layer "F.Cu")
		(net "M_A_CPU0_SB_CB<2>")
	)
	(segment
		(start 318.8208 -235.439458)
		(end 318.51092 -235.439458)
		(width 0.20066)
		(layer "F.Cu")
		(net "M_A_CPU0_SB_CB<2>")
	)
	(segment
		(start 310.01208 -235.141516)
		(end 310.153304 -235.141516)
		(width 0.101854)
		(layer "F.Cu")
		(net "M_A_CPU0_SB_CB<2>")
	)
	(segment
		(start 331.91831 -239.064038)
		(end 331.836522 -238.98225)
		(width 0.088646)
		(layer "F.Cu")
		(net "M_A_CPU0_SB_CB<2>")
	)
	(segment
		(start 319.22212 -235.937806)
		(end 319.02146 -235.737146)
		(width 0.20066)
		(layer "F.Cu")
		(net "M_A_CPU0_SB_CB<2>")
	)
	(arc
		(start 334.440784 -239.168432)
		(mid 334.205834 -239.105472)
		(end 333.970884 -239.168432)
		(width 0.088646)
		(layer "F.Cu")
		(net "M_A_CPU0_SB_CB<2>")
	)
	(arc
		(start 333.500984 -239.168432)
		(mid 333.193401 -239.107061)
		(end 332.912212 -239.245902)
		(width 0.088646)
		(layer "F.Cu")
		(net "M_A_CPU0_SB_CB<2>")
	)
	(arc
		(start 333.970884 -239.168432)
		(mid 333.735934 -239.231392)
		(end 333.500984 -239.168432)
		(width 0.088646)
		(layer "F.Cu")
		(net "M_A_CPU0_SB_CB<2>")
	)
	(segment
		(start 316.059058 -234.6452)
		(end 314.855606 -233.441748)
		(width 0.20066)
		(layer "F.Cu")
		(net "M_A_CPU0_SB_CB<1>")
	)
	(segment
		(start 306.83581 -233.441748)
		(end 307.31079 -233.916728)
		(width 0.20066)
		(layer "F.Cu")
		(net "M_A_CPU0_SB_CB<1>")
	)
	(segment
		(start 311.715404 -233.441748)
		(end 311.192164 -233.441748)
		(width 0.20066)
		(layer "F.Cu")
		(net "M_A_CPU0_SB_CB<1>")
	)
	(segment
		(start 303.483772 -234.103672)
		(end 303.684432 -233.903012)
		(width 0.20066)
		(layer "F.Cu")
		(net "M_A_CPU0_SB_CB<1>")
	)
	(segment
		(start 334.046576 -238.761524)
		(end 334.105758 -238.702342)
		(width 0.088646)
		(layer "F.Cu")
		(net "M_A_CPU0_SB_CB<1>")
	)
	(segment
		(start 310.767222 -233.86669)
		(end 308.887114 -233.86669)
		(width 0.20066)
		(layer "F.Cu")
		(net "M_A_CPU0_SB_CB<1>")
	)
	(segment
		(start 303.684432 -233.61142)
		(end 303.854104 -233.441748)
		(width 0.20066)
		(layer "F.Cu")
		(net "M_A_CPU0_SB_CB<1>")
	)
	(segment
		(start 314.11672 -233.441748)
		(end 311.934098 -233.441748)
		(width 0.1016)
		(layer "F.Cu")
		(net "M_A_CPU0_SB_CB<1>")
	)
	(segment
		(start 323.658738 -234.6452)
		(end 316.059058 -234.6452)
		(width 0.20066)
		(layer "F.Cu")
		(net "M_A_CPU0_SB_CB<1>")
	)
	(segment
		(start 332.147164 -238.204502)
		(end 331.609446 -238.204502)
		(width 0.1016)
		(layer "F.Cu")
		(net "M_A_CPU0_SB_CB<1>")
	)
	(segment
		(start 314.26023 -233.441748)
		(end 314.11672 -233.441748)
		(width 0.101854)
		(layer "F.Cu")
		(net "M_A_CPU0_SB_CB<1>")
	)
	(segment
		(start 314.855606 -233.441748)
		(end 314.26023 -233.441748)
		(width 0.20066)
		(layer "F.Cu")
		(net "M_A_CPU0_SB_CB<1>")
	)
	(segment
		(start 331.50556 -238.100616)
		(end 329.697334 -238.100616)
		(width 0.1016)
		(layer "F.Cu")
		(net "M_A_CPU0_SB_CB<1>")
	)
	(segment
		(start 328.327512 -236.926628)
		(end 325.940166 -236.926628)
		(width 0.20066)
		(layer "F.Cu")
		(net "M_A_CPU0_SB_CB<1>")
	)
	(segment
		(start 304.185574 -233.441748)
		(end 304.550826 -233.441748)
		(width 0.101854)
		(layer "F.Cu")
		(net "M_A_CPU0_SB_CB<1>")
	)
	(segment
		(start 325.940166 -236.926628)
		(end 323.658738 -234.6452)
		(width 0.20066)
		(layer "F.Cu")
		(net "M_A_CPU0_SB_CB<1>")
	)
	(segment
		(start 306.289202 -233.441748)
		(end 306.708302 -233.441748)
		(width 0.101854)
		(layer "F.Cu")
		(net "M_A_CPU0_SB_CB<1>")
	)
	(segment
		(start 301.343314 -233.86669)
		(end 302.900334 -233.86669)
		(width 0.20066)
		(layer "F.Cu")
		(net "M_A_CPU0_SB_CB<1>")
	)
	(segment
		(start 333.735934 -238.761524)
		(end 334.046576 -238.761524)
		(width 0.088646)
		(layer "F.Cu")
		(net "M_A_CPU0_SB_CB<1>")
	)
	(segment
		(start 304.550826 -233.441748)
		(end 306.289202 -233.441748)
		(width 0.1016)
		(layer "F.Cu")
		(net "M_A_CPU0_SB_CB<1>")
	)
	(segment
		(start 332.723236 -238.204502)
		(end 332.147164 -238.204502)
		(width 0.088646)
		(layer "F.Cu")
		(net "M_A_CPU0_SB_CB<1>")
	)
	(segment
		(start 311.934098 -233.441748)
		(end 311.715404 -233.441748)
		(width 0.101854)
		(layer "F.Cu")
		(net "M_A_CPU0_SB_CB<1>")
	)
	(segment
		(start 329.697334 -238.100616)
		(end 328.523346 -236.926628)
		(width 0.1016)
		(layer "F.Cu")
		(net "M_A_CPU0_SB_CB<1>")
	)
	(segment
		(start 328.523346 -236.926628)
		(end 328.327512 -236.926628)
		(width 0.1016)
		(layer "F.Cu")
		(net "M_A_CPU0_SB_CB<1>")
	)
	(segment
		(start 306.708302 -233.441748)
		(end 306.83581 -233.441748)
		(width 0.20066)
		(layer "F.Cu")
		(net "M_A_CPU0_SB_CB<1>")
	)
	(segment
		(start 303.854104 -233.441748)
		(end 304.185574 -233.441748)
		(width 0.20066)
		(layer "F.Cu")
		(net "M_A_CPU0_SB_CB<1>")
	)
	(segment
		(start 308.0131 -233.916728)
		(end 308.063138 -233.86669)
		(width 0.20066)
		(layer "F.Cu")
		(net "M_A_CPU0_SB_CB<1>")
	)
	(segment
		(start 307.31079 -233.916728)
		(end 308.0131 -233.916728)
		(width 0.20066)
		(layer "F.Cu")
		(net "M_A_CPU0_SB_CB<1>")
	)
	(segment
		(start 331.609446 -238.204502)
		(end 331.50556 -238.100616)
		(width 0.1016)
		(layer "F.Cu")
		(net "M_A_CPU0_SB_CB<1>")
	)
	(segment
		(start 302.900334 -233.86669)
		(end 303.137316 -234.103672)
		(width 0.20066)
		(layer "F.Cu")
		(net "M_A_CPU0_SB_CB<1>")
	)
	(segment
		(start 332.865984 -238.347504)
		(end 332.723236 -238.204502)
		(width 0.088646)
		(layer "F.Cu")
		(net "M_A_CPU0_SB_CB<1>")
	)
	(segment
		(start 311.192164 -233.441748)
		(end 310.767222 -233.86669)
		(width 0.20066)
		(layer "F.Cu")
		(net "M_A_CPU0_SB_CB<1>")
	)
	(segment
		(start 303.137316 -234.103672)
		(end 303.483772 -234.103672)
		(width 0.20066)
		(layer "F.Cu")
		(net "M_A_CPU0_SB_CB<1>")
	)
	(segment
		(start 308.063138 -233.86669)
		(end 308.887114 -233.86669)
		(width 0.20066)
		(layer "F.Cu")
		(net "M_A_CPU0_SB_CB<1>")
	)
	(segment
		(start 303.684432 -233.903012)
		(end 303.684432 -233.61142)
		(width 0.20066)
		(layer "F.Cu")
		(net "M_A_CPU0_SB_CB<1>")
	)
	(arc
		(start 333.932022 -238.442246)
		(mid 333.837812 -238.400984)
		(end 333.735934 -238.386874)
		(width 0.088646)
		(layer "F.Cu")
		(net "M_A_CPU0_SB_CB<1>")
	)
	(arc
		(start 333.735934 -238.386874)
		(mid 333.639033 -238.399554)
		(end 333.548736 -238.436912)
		(width 0.088646)
		(layer "F.Cu")
		(net "M_A_CPU0_SB_CB<1>")
	)
	(arc
		(start 332.99908 -238.445802)
		(mid 332.928923 -238.401541)
		(end 332.865984 -238.347504)
		(width 0.088646)
		(layer "F.Cu")
		(net "M_A_CPU0_SB_CB<1>")
	)
	(arc
		(start 334.105758 -238.702342)
		(mid 334.047379 -238.553246)
		(end 333.932022 -238.442246)
		(width 0.088646)
		(layer "F.Cu")
		(net "M_A_CPU0_SB_CB<1>")
	)
	(arc
		(start 333.543402 -238.439706)
		(mid 333.272033 -238.512595)
		(end 332.99908 -238.445802)
		(width 0.088646)
		(layer "F.Cu")
		(net "M_A_CPU0_SB_CB<1>")
	)
	(arc
		(start 333.548736 -238.436912)
		(mid 333.546102 -238.438372)
		(end 333.543402 -238.439706)
		(width 0.088646)
		(layer "F.Cu")
		(net "M_A_CPU0_SB_CB<1>")
	)
	(segment
		(start 332.032864 -239.611408)
		(end 331.620114 -239.198658)
		(width 0.088646)
		(layer "F.Cu")
		(net "M_A_CPU0_SB_CB<0>")
	)
	(segment
		(start 303.322736 -235.783374)
		(end 303.523396 -235.582714)
		(width 0.20066)
		(layer "F.Cu")
		(net "M_A_CPU0_SB_CB<0>")
	)
	(segment
		(start 314.473844 -235.141516)
		(end 313.843416 -235.141516)
		(width 0.101854)
		(layer "F.Cu")
		(net "M_A_CPU0_SB_CB<0>")
	)
	(segment
		(start 310.767222 -235.566712)
		(end 308.887114 -235.566712)
		(width 0.20066)
		(layer "F.Cu")
		(net "M_A_CPU0_SB_CB<0>")
	)
	(segment
		(start 328.983848 -238.249968)
		(end 328.495152 -238.249968)
		(width 0.1016)
		(layer "F.Cu")
		(net "M_A_CPU0_SB_CB<0>")
	)
	(segment
		(start 306.289202 -235.141516)
		(end 306.923948 -235.141516)
		(width 0.101854)
		(layer "F.Cu")
		(net "M_A_CPU0_SB_CB<0>")
	)
	(segment
		(start 301.343314 -235.566712)
		(end 301.39132 -235.518706)
		(width 0.20066)
		(layer "F.Cu")
		(net "M_A_CPU0_SB_CB<0>")
	)
	(segment
		(start 311.192418 -235.141516)
		(end 310.767222 -235.566712)
		(width 0.20066)
		(layer "F.Cu")
		(net "M_A_CPU0_SB_CB<0>")
	)
	(segment
		(start 331.131672 -238.710216)
		(end 329.444096 -238.710216)
		(width 0.1016)
		(layer "F.Cu")
		(net "M_A_CPU0_SB_CB<0>")
	)
	(segment
		(start 328.495152 -238.249968)
		(end 325.348346 -238.249968)
		(width 0.20066)
		(layer "F.Cu")
		(net "M_A_CPU0_SB_CB<0>")
	)
	(segment
		(start 303.523396 -235.582714)
		(end 303.523396 -235.342176)
		(width 0.20066)
		(layer "F.Cu")
		(net "M_A_CPU0_SB_CB<0>")
	)
	(segment
		(start 306.969668 -235.141516)
		(end 307.394864 -235.566712)
		(width 0.20066)
		(layer "F.Cu")
		(net "M_A_CPU0_SB_CB<0>")
	)
	(segment
		(start 333.229712 -239.611408)
		(end 332.032864 -239.611408)
		(width 0.088646)
		(layer "F.Cu")
		(net "M_A_CPU0_SB_CB<0>")
	)
	(segment
		(start 303.523396 -235.342176)
		(end 303.724056 -235.141516)
		(width 0.20066)
		(layer "F.Cu")
		(net "M_A_CPU0_SB_CB<0>")
	)
	(segment
		(start 307.394864 -235.566712)
		(end 308.887114 -235.566712)
		(width 0.20066)
		(layer "F.Cu")
		(net "M_A_CPU0_SB_CB<0>")
	)
	(segment
		(start 311.5183 -235.141516)
		(end 311.192418 -235.141516)
		(width 0.20066)
		(layer "F.Cu")
		(net "M_A_CPU0_SB_CB<0>")
	)
	(segment
		(start 325.348346 -238.249968)
		(end 323.702934 -236.604556)
		(width 0.20066)
		(layer "F.Cu")
		(net "M_A_CPU0_SB_CB<0>")
	)
	(segment
		(start 333.26578 -239.57534)
		(end 333.229712 -239.611408)
		(width 0.088646)
		(layer "F.Cu")
		(net "M_A_CPU0_SB_CB<0>")
	)
	(segment
		(start 331.620114 -239.198658)
		(end 331.131672 -238.710216)
		(width 0.101854)
		(layer "F.Cu")
		(net "M_A_CPU0_SB_CB<0>")
	)
	(segment
		(start 314.778644 -235.69803)
		(end 314.778644 -235.249212)
		(width 0.20066)
		(layer "F.Cu")
		(net "M_A_CPU0_SB_CB<0>")
	)
	(segment
		(start 315.226446 -236.145832)
		(end 314.778644 -235.69803)
		(width 0.20066)
		(layer "F.Cu")
		(net "M_A_CPU0_SB_CB<0>")
	)
	(segment
		(start 303.984406 -235.141516)
		(end 304.550826 -235.141516)
		(width 0.101854)
		(layer "F.Cu")
		(net "M_A_CPU0_SB_CB<0>")
	)
	(segment
		(start 304.550826 -235.141516)
		(end 306.289202 -235.141516)
		(width 0.1016)
		(layer "F.Cu")
		(net "M_A_CPU0_SB_CB<0>")
	)
	(segment
		(start 316.226698 -236.145832)
		(end 315.226446 -236.145832)
		(width 0.20066)
		(layer "F.Cu")
		(net "M_A_CPU0_SB_CB<0>")
	)
	(segment
		(start 303.724056 -235.141516)
		(end 303.984406 -235.141516)
		(width 0.20066)
		(layer "F.Cu")
		(net "M_A_CPU0_SB_CB<0>")
	)
	(segment
		(start 303.013364 -235.783374)
		(end 303.322736 -235.783374)
		(width 0.20066)
		(layer "F.Cu")
		(net "M_A_CPU0_SB_CB<0>")
	)
	(segment
		(start 316.685422 -236.604556)
		(end 316.226698 -236.145832)
		(width 0.20066)
		(layer "F.Cu")
		(net "M_A_CPU0_SB_CB<0>")
	)
	(segment
		(start 313.843416 -235.141516)
		(end 312.12536 -235.141516)
		(width 0.1016)
		(layer "F.Cu")
		(net "M_A_CPU0_SB_CB<0>")
	)
	(segment
		(start 301.39132 -235.518706)
		(end 302.748696 -235.518706)
		(width 0.20066)
		(layer "F.Cu")
		(net "M_A_CPU0_SB_CB<0>")
	)
	(segment
		(start 312.12536 -235.141516)
		(end 311.5183 -235.141516)
		(width 0.101854)
		(layer "F.Cu")
		(net "M_A_CPU0_SB_CB<0>")
	)
	(segment
		(start 323.702934 -236.604556)
		(end 316.685422 -236.604556)
		(width 0.20066)
		(layer "F.Cu")
		(net "M_A_CPU0_SB_CB<0>")
	)
	(segment
		(start 302.748696 -235.518706)
		(end 303.013364 -235.783374)
		(width 0.20066)
		(layer "F.Cu")
		(net "M_A_CPU0_SB_CB<0>")
	)
	(segment
		(start 314.778644 -235.249212)
		(end 314.670948 -235.141516)
		(width 0.20066)
		(layer "F.Cu")
		(net "M_A_CPU0_SB_CB<0>")
	)
	(segment
		(start 314.670948 -235.141516)
		(end 314.473844 -235.141516)
		(width 0.20066)
		(layer "F.Cu")
		(net "M_A_CPU0_SB_CB<0>")
	)
	(segment
		(start 329.444096 -238.710216)
		(end 328.983848 -238.249968)
		(width 0.1016)
		(layer "F.Cu")
		(net "M_A_CPU0_SB_CB<0>")
	)
	(segment
		(start 306.923948 -235.141516)
		(end 306.969668 -235.141516)
		(width 0.20066)
		(layer "F.Cu")
		(net "M_A_CPU0_SB_CB<0>")
	)
	(segment
		(start 320.923666 -247.640348)
		(end 320.513202 -248.050812)
		(width 0.20066)
		(layer "F.Cu")
		(net "M_A_CPU0_SB_CA<6>")
	)
	(segment
		(start 331.296264 -245.51894)
		(end 329.323192 -247.492012)
		(width 0.1016)
		(layer "F.Cu")
		(net "M_A_CPU0_SB_CA<6>")
	)
	(segment
		(start 332.796134 -245.27256)
		(end 332.549754 -245.51894)
		(width 0.088646)
		(layer "F.Cu")
		(net "M_A_CPU0_SB_CA<6>")
	)
	(segment
		(start 307.473096 -247.466612)
		(end 308.887114 -247.466612)
		(width 0.20066)
		(layer "F.Cu")
		(net "M_A_CPU0_SB_CA<6>")
	)
	(segment
		(start 306.644294 -247.891554)
		(end 307.048154 -247.891554)
		(width 0.20066)
		(layer "F.Cu")
		(net "M_A_CPU0_SB_CA<6>")
	)
	(segment
		(start 303.15027 -248.35739)
		(end 303.709324 -248.35739)
		(width 0.20066)
		(layer "F.Cu")
		(net "M_A_CPU0_SB_CA<6>")
	)
	(segment
		(start 304.385726 -247.904762)
		(end 304.398934 -247.891554)
		(width 0.101854)
		(layer "F.Cu")
		(net "M_A_CPU0_SB_CA<6>")
	)
	(segment
		(start 311.91708 -247.899428)
		(end 311.68975 -247.899428)
		(width 0.20066)
		(layer "F.Cu")
		(net "M_A_CPU0_SB_CA<6>")
	)
	(segment
		(start 332.549754 -245.51894)
		(end 332.070964 -245.51894)
		(width 0.088646)
		(layer "F.Cu")
		(net "M_A_CPU0_SB_CA<6>")
	)
	(segment
		(start 320.513202 -248.050812)
		(end 315.630814 -248.050812)
		(width 0.20066)
		(layer "F.Cu")
		(net "M_A_CPU0_SB_CA<6>")
	)
	(segment
		(start 307.048154 -247.891554)
		(end 307.473096 -247.466612)
		(width 0.20066)
		(layer "F.Cu")
		(net "M_A_CPU0_SB_CA<6>")
	)
	(segment
		(start 304.398934 -247.891554)
		(end 306.58308 -247.891554)
		(width 0.1016)
		(layer "F.Cu")
		(net "M_A_CPU0_SB_CA<6>")
	)
	(segment
		(start 302.259492 -247.466612)
		(end 303.15027 -248.35739)
		(width 0.20066)
		(layer "F.Cu")
		(net "M_A_CPU0_SB_CA<6>")
	)
	(segment
		(start 303.709324 -248.35739)
		(end 304.161952 -247.904762)
		(width 0.20066)
		(layer "F.Cu")
		(net "M_A_CPU0_SB_CA<6>")
	)
	(segment
		(start 321.072002 -247.492012)
		(end 320.923666 -247.640348)
		(width 0.1016)
		(layer "F.Cu")
		(net "M_A_CPU0_SB_CA<6>")
	)
	(segment
		(start 304.319178 -247.904762)
		(end 304.385726 -247.904762)
		(width 0.101854)
		(layer "F.Cu")
		(net "M_A_CPU0_SB_CA<6>")
	)
	(segment
		(start 304.161952 -247.904762)
		(end 304.319178 -247.904762)
		(width 0.20066)
		(layer "F.Cu")
		(net "M_A_CPU0_SB_CA<6>")
	)
	(segment
		(start 332.070964 -245.51894)
		(end 331.296264 -245.51894)
		(width 0.1016)
		(layer "F.Cu")
		(net "M_A_CPU0_SB_CA<6>")
	)
	(segment
		(start 306.58308 -247.891554)
		(end 306.644294 -247.891554)
		(width 0.101854)
		(layer "F.Cu")
		(net "M_A_CPU0_SB_CA<6>")
	)
	(segment
		(start 314.057792 -247.891554)
		(end 311.933336 -247.891554)
		(width 0.1016)
		(layer "F.Cu")
		(net "M_A_CPU0_SB_CA<6>")
	)
	(segment
		(start 315.487812 -247.90781)
		(end 314.12688 -247.90781)
		(width 0.20066)
		(layer "F.Cu")
		(net "M_A_CPU0_SB_CA<6>")
	)
	(segment
		(start 311.68975 -247.899428)
		(end 311.256934 -247.466612)
		(width 0.20066)
		(layer "F.Cu")
		(net "M_A_CPU0_SB_CA<6>")
	)
	(segment
		(start 329.323192 -247.492012)
		(end 321.072002 -247.492012)
		(width 0.1016)
		(layer "F.Cu")
		(net "M_A_CPU0_SB_CA<6>")
	)
	(segment
		(start 311.256934 -247.466612)
		(end 308.887114 -247.466612)
		(width 0.20066)
		(layer "F.Cu")
		(net "M_A_CPU0_SB_CA<6>")
	)
	(segment
		(start 314.12688 -247.90781)
		(end 314.074048 -247.90781)
		(width 0.101854)
		(layer "F.Cu")
		(net "M_A_CPU0_SB_CA<6>")
	)
	(segment
		(start 311.933336 -247.891554)
		(end 311.925462 -247.899428)
		(width 0.101854)
		(layer "F.Cu")
		(net "M_A_CPU0_SB_CA<6>")
	)
	(segment
		(start 311.925462 -247.899428)
		(end 311.91708 -247.899428)
		(width 0.101854)
		(layer "F.Cu")
		(net "M_A_CPU0_SB_CA<6>")
	)
	(segment
		(start 314.074048 -247.90781)
		(end 314.057792 -247.891554)
		(width 0.101854)
		(layer "F.Cu")
		(net "M_A_CPU0_SB_CA<6>")
	)
	(segment
		(start 301.343314 -247.466612)
		(end 302.259492 -247.466612)
		(width 0.20066)
		(layer "F.Cu")
		(net "M_A_CPU0_SB_CA<6>")
	)
	(segment
		(start 315.630814 -248.050812)
		(end 315.487812 -247.90781)
		(width 0.20066)
		(layer "F.Cu")
		(net "M_A_CPU0_SB_CA<6>")
	)
	(segment
		(start 307.564028 -248.758456)
		(end 307.76291 -248.758456)
		(width 0.20066)
		(layer "F.Cu")
		(net "M_A_CPU0_SB_CA<5>")
	)
	(segment
		(start 333.045308 -245.746524)
		(end 332.975712 -245.78437)
		(width 0.088646)
		(layer "F.Cu")
		(net "M_A_CPU0_SB_CA<5>")
	)
	(segment
		(start 307.121814 -248.31675)
		(end 307.122068 -248.316496)
		(width 0.20066)
		(layer "F.Cu")
		(net "M_A_CPU0_SB_CA<5>")
	)
	(segment
		(start 332.79461 -245.829836)
		(end 332.791308 -245.826534)
		(width 0.088646)
		(layer "F.Cu")
		(net "M_A_CPU0_SB_CA<5>")
	)
	(segment
		(start 307.122068 -248.316496)
		(end 307.564028 -248.758456)
		(width 0.20066)
		(layer "F.Cu")
		(net "M_A_CPU0_SB_CA<5>")
	)
	(segment
		(start 310.56072 -248.396252)
		(end 310.70804 -248.248932)
		(width 0.20066)
		(layer "F.Cu")
		(net "M_A_CPU0_SB_CA<5>")
	)
	(segment
		(start 314.34532 -248.61647)
		(end 314.0456 -248.31675)
		(width 0.20066)
		(layer "F.Cu")
		(net "M_A_CPU0_SB_CA<5>")
	)
	(segment
		(start 307.836316 -248.758456)
		(end 307.85308 -248.741692)
		(width 0.101854)
		(layer "F.Cu")
		(net "M_A_CPU0_SB_CA<5>")
	)
	(segment
		(start 334.768444 -246.463566)
		(end 334.214978 -246.463566)
		(width 0.088646)
		(layer "F.Cu")
		(net "M_A_CPU0_SB_CA<5>")
	)
	(segment
		(start 315.431678 -249.287538)
		(end 314.76061 -248.61647)
		(width 0.20066)
		(layer "F.Cu")
		(net "M_A_CPU0_SB_CA<5>")
	)
	(segment
		(start 310.99252 -248.248932)
		(end 311.27192 -248.528332)
		(width 0.20066)
		(layer "F.Cu")
		(net "M_A_CPU0_SB_CA<5>")
	)
	(segment
		(start 307.85308 -248.741692)
		(end 310.01208 -248.741692)
		(width 0.1016)
		(layer "F.Cu")
		(net "M_A_CPU0_SB_CA<5>")
	)
	(segment
		(start 333.52867 -245.761764)
		(end 333.49819 -245.744238)
		(width 0.088646)
		(layer "F.Cu")
		(net "M_A_CPU0_SB_CA<5>")
	)
	(segment
		(start 331.419962 -245.826534)
		(end 329.449684 -247.796812)
		(width 0.1016)
		(layer "F.Cu")
		(net "M_A_CPU0_SB_CA<5>")
	)
	(segment
		(start 329.449684 -247.796812)
		(end 321.707764 -247.796812)
		(width 0.1016)
		(layer "F.Cu")
		(net "M_A_CPU0_SB_CA<5>")
	)
	(segment
		(start 311.27192 -248.528332)
		(end 311.948322 -248.528332)
		(width 0.20066)
		(layer "F.Cu")
		(net "M_A_CPU0_SB_CA<5>")
	)
	(segment
		(start 334.018636 -246.410988)
		(end 333.846424 -246.31142)
		(width 0.088646)
		(layer "F.Cu")
		(net "M_A_CPU0_SB_CA<5>")
	)
	(segment
		(start 320.217038 -249.287538)
		(end 315.431678 -249.287538)
		(width 0.20066)
		(layer "F.Cu")
		(net "M_A_CPU0_SB_CA<5>")
	)
	(segment
		(start 310.01208 -248.741692)
		(end 310.088026 -248.741692)
		(width 0.101854)
		(layer "F.Cu")
		(net "M_A_CPU0_SB_CA<5>")
	)
	(segment
		(start 312.159904 -248.31675)
		(end 312.987182 -248.31675)
		(width 0.20066)
		(layer "F.Cu")
		(net "M_A_CPU0_SB_CA<5>")
	)
	(segment
		(start 332.791308 -245.826534)
		(end 332.070964 -245.826534)
		(width 0.088646)
		(layer "F.Cu")
		(net "M_A_CPU0_SB_CA<5>")
	)
	(segment
		(start 310.4388 -248.741692)
		(end 310.56072 -248.619772)
		(width 0.20066)
		(layer "F.Cu")
		(net "M_A_CPU0_SB_CA<5>")
	)
	(segment
		(start 314.0456 -248.31675)
		(end 312.987182 -248.31675)
		(width 0.20066)
		(layer "F.Cu")
		(net "M_A_CPU0_SB_CA<5>")
	)
	(segment
		(start 332.070964 -245.826534)
		(end 331.419962 -245.826534)
		(width 0.1016)
		(layer "F.Cu")
		(net "M_A_CPU0_SB_CA<5>")
	)
	(segment
		(start 310.70804 -248.248932)
		(end 310.99252 -248.248932)
		(width 0.20066)
		(layer "F.Cu")
		(net "M_A_CPU0_SB_CA<5>")
	)
	(segment
		(start 305.443382 -248.31675)
		(end 307.121814 -248.31675)
		(width 0.20066)
		(layer "F.Cu")
		(net "M_A_CPU0_SB_CA<5>")
	)
	(segment
		(start 310.088026 -248.741692)
		(end 310.4388 -248.741692)
		(width 0.20066)
		(layer "F.Cu")
		(net "M_A_CPU0_SB_CA<5>")
	)
	(segment
		(start 307.76291 -248.758456)
		(end 307.836316 -248.758456)
		(width 0.101854)
		(layer "F.Cu")
		(net "M_A_CPU0_SB_CA<5>")
	)
	(segment
		(start 321.498976 -248.0056)
		(end 320.217038 -249.287538)
		(width 0.20066)
		(layer "F.Cu")
		(net "M_A_CPU0_SB_CA<5>")
	)
	(segment
		(start 311.948322 -248.528332)
		(end 312.159904 -248.31675)
		(width 0.20066)
		(layer "F.Cu")
		(net "M_A_CPU0_SB_CA<5>")
	)
	(segment
		(start 314.76061 -248.61647)
		(end 314.34532 -248.61647)
		(width 0.20066)
		(layer "F.Cu")
		(net "M_A_CPU0_SB_CA<5>")
	)
	(segment
		(start 321.707764 -247.796812)
		(end 321.498976 -248.0056)
		(width 0.1016)
		(layer "F.Cu")
		(net "M_A_CPU0_SB_CA<5>")
	)
	(segment
		(start 310.56072 -248.619772)
		(end 310.56072 -248.396252)
		(width 0.20066)
		(layer "F.Cu")
		(net "M_A_CPU0_SB_CA<5>")
	)
	(segment
		(start 335.14538 -246.08663)
		(end 334.768444 -246.463566)
		(width 0.088646)
		(layer "F.Cu")
		(net "M_A_CPU0_SB_CA<5>")
	)
	(arc
		(start 333.846424 -246.31142)
		(mid 333.779336 -246.244309)
		(end 333.75473 -246.15267)
		(width 0.088646)
		(layer "F.Cu")
		(net "M_A_CPU0_SB_CA<5>")
	)
	(arc
		(start 333.75473 -246.15267)
		(mid 333.694154 -245.926876)
		(end 333.52867 -245.761764)
		(width 0.088646)
		(layer "F.Cu")
		(net "M_A_CPU0_SB_CA<5>")
	)
	(arc
		(start 333.49819 -245.744238)
		(mid 333.271432 -245.684447)
		(end 333.045308 -245.746524)
		(width 0.088646)
		(layer "F.Cu")
		(net "M_A_CPU0_SB_CA<5>")
	)
	(arc
		(start 334.214978 -246.463566)
		(mid 334.113347 -246.450195)
		(end 334.018636 -246.410988)
		(width 0.088646)
		(layer "F.Cu")
		(net "M_A_CPU0_SB_CA<5>")
	)
	(arc
		(start 332.975712 -245.78437)
		(mid 332.887973 -245.818308)
		(end 332.79461 -245.829836)
		(width 0.088646)
		(layer "F.Cu")
		(net "M_A_CPU0_SB_CA<5>")
	)
	(segment
		(start 304.37201 -249.63628)
		(end 304.416714 -249.591576)
		(width 0.101854)
		(layer "F.Cu")
		(net "M_A_CPU0_SB_CA<4>")
	)
	(segment
		(start 306.644294 -249.591576)
		(end 307.047646 -249.591576)
		(width 0.20066)
		(layer "F.Cu")
		(net "M_A_CPU0_SB_CA<4>")
	)
	(segment
		(start 311.926478 -249.591576)
		(end 311.91708 -249.600974)
		(width 0.101854)
		(layer "F.Cu")
		(net "M_A_CPU0_SB_CA<4>")
	)
	(segment
		(start 307.047646 -249.591576)
		(end 307.472588 -249.166634)
		(width 0.20066)
		(layer "F.Cu")
		(net "M_A_CPU0_SB_CA<4>")
	)
	(segment
		(start 311.33415 -249.600974)
		(end 310.899556 -249.16638)
		(width 0.20066)
		(layer "F.Cu")
		(net "M_A_CPU0_SB_CA<4>")
	)
	(segment
		(start 315.028326 -250.150122)
		(end 314.4901 -249.611896)
		(width 0.20066)
		(layer "F.Cu")
		(net "M_A_CPU0_SB_CA<4>")
	)
	(segment
		(start 310.899302 -249.166634)
		(end 308.887114 -249.166634)
		(width 0.20066)
		(layer "F.Cu")
		(net "M_A_CPU0_SB_CA<4>")
	)
	(segment
		(start 302.24349 -249.166634)
		(end 303.14646 -250.069604)
		(width 0.20066)
		(layer "F.Cu")
		(net "M_A_CPU0_SB_CA<4>")
	)
	(segment
		(start 314.4901 -249.611896)
		(end 314.12688 -249.611896)
		(width 0.20066)
		(layer "F.Cu")
		(net "M_A_CPU0_SB_CA<4>")
	)
	(segment
		(start 304.319178 -249.63628)
		(end 304.37201 -249.63628)
		(width 0.101854)
		(layer "F.Cu")
		(net "M_A_CPU0_SB_CA<4>")
	)
	(segment
		(start 332.845156 -246.170196)
		(end 331.816964 -246.170196)
		(width 0.088646)
		(layer "F.Cu")
		(net "M_A_CPU0_SB_CA<4>")
	)
	(segment
		(start 311.91708 -249.600974)
		(end 311.33415 -249.600974)
		(width 0.20066)
		(layer "F.Cu")
		(net "M_A_CPU0_SB_CA<4>")
	)
	(segment
		(start 314.10656 -249.591576)
		(end 313.828684 -249.591576)
		(width 0.101854)
		(layer "F.Cu")
		(net "M_A_CPU0_SB_CA<4>")
	)
	(segment
		(start 329.576176 -248.101612)
		(end 322.308728 -248.101612)
		(width 0.1016)
		(layer "F.Cu")
		(net "M_A_CPU0_SB_CA<4>")
	)
	(segment
		(start 331.816964 -246.170196)
		(end 331.507592 -246.170196)
		(width 0.1016)
		(layer "F.Cu")
		(net "M_A_CPU0_SB_CA<4>")
	)
	(segment
		(start 322.088002 -248.322338)
		(end 320.260218 -250.150122)
		(width 0.20066)
		(layer "F.Cu")
		(net "M_A_CPU0_SB_CA<4>")
	)
	(segment
		(start 313.828684 -249.591576)
		(end 312.059574 -249.591576)
		(width 0.1016)
		(layer "F.Cu")
		(net "M_A_CPU0_SB_CA<4>")
	)
	(segment
		(start 310.899556 -249.16638)
		(end 310.899302 -249.166634)
		(width 0.20066)
		(layer "F.Cu")
		(net "M_A_CPU0_SB_CA<4>")
	)
	(segment
		(start 333.26578 -246.08663)
		(end 332.845156 -246.170196)
		(width 0.088646)
		(layer "F.Cu")
		(net "M_A_CPU0_SB_CA<4>")
	)
	(segment
		(start 314.12688 -249.611896)
		(end 314.10656 -249.591576)
		(width 0.101854)
		(layer "F.Cu")
		(net "M_A_CPU0_SB_CA<4>")
	)
	(segment
		(start 301.343314 -249.166634)
		(end 302.24349 -249.166634)
		(width 0.20066)
		(layer "F.Cu")
		(net "M_A_CPU0_SB_CA<4>")
	)
	(segment
		(start 304.416714 -249.591576)
		(end 306.58308 -249.591576)
		(width 0.1016)
		(layer "F.Cu")
		(net "M_A_CPU0_SB_CA<4>")
	)
	(segment
		(start 331.507592 -246.170196)
		(end 329.576176 -248.101612)
		(width 0.1016)
		(layer "F.Cu")
		(net "M_A_CPU0_SB_CA<4>")
	)
	(segment
		(start 303.672748 -250.069604)
		(end 304.106072 -249.63628)
		(width 0.20066)
		(layer "F.Cu")
		(net "M_A_CPU0_SB_CA<4>")
	)
	(segment
		(start 320.260218 -250.150122)
		(end 315.028326 -250.150122)
		(width 0.20066)
		(layer "F.Cu")
		(net "M_A_CPU0_SB_CA<4>")
	)
	(segment
		(start 303.14646 -250.069604)
		(end 303.672748 -250.069604)
		(width 0.20066)
		(layer "F.Cu")
		(net "M_A_CPU0_SB_CA<4>")
	)
	(segment
		(start 307.472588 -249.166634)
		(end 308.887114 -249.166634)
		(width 0.20066)
		(layer "F.Cu")
		(net "M_A_CPU0_SB_CA<4>")
	)
	(segment
		(start 304.106072 -249.63628)
		(end 304.319178 -249.63628)
		(width 0.20066)
		(layer "F.Cu")
		(net "M_A_CPU0_SB_CA<4>")
	)
	(segment
		(start 306.58308 -249.591576)
		(end 306.644294 -249.591576)
		(width 0.101854)
		(layer "F.Cu")
		(net "M_A_CPU0_SB_CA<4>")
	)
	(segment
		(start 312.059574 -249.591576)
		(end 311.926478 -249.591576)
		(width 0.101854)
		(layer "F.Cu")
		(net "M_A_CPU0_SB_CA<4>")
	)
	(segment
		(start 322.308728 -248.101612)
		(end 322.088002 -248.322338)
		(width 0.1016)
		(layer "F.Cu")
		(net "M_A_CPU0_SB_CA<4>")
	)
	(segment
		(start 315.072776 -250.91009)
		(end 314.727336 -250.766834)
		(width 0.20066)
		(layer "F.Cu")
		(net "M_A_CPU0_SB_CA<3>")
	)
	(segment
		(start 307.808122 -250.461272)
		(end 307.82768 -250.441714)
		(width 0.101854)
		(layer "F.Cu")
		(net "M_A_CPU0_SB_CA<3>")
	)
	(segment
		(start 311.272174 -250.08586)
		(end 311.602374 -250.41606)
		(width 0.20066)
		(layer "F.Cu")
		(net "M_A_CPU0_SB_CA<3>")
	)
	(segment
		(start 331.907896 -246.518176)
		(end 331.848714 -246.577358)
		(width 0.088646)
		(layer "F.Cu")
		(net "M_A_CPU0_SB_CA<3>")
	)
	(segment
		(start 307.82768 -250.441714)
		(end 310.01208 -250.441714)
		(width 0.1016)
		(layer "F.Cu")
		(net "M_A_CPU0_SB_CA<3>")
	)
	(segment
		(start 334.675734 -246.900446)
		(end 333.951072 -246.592344)
		(width 0.088646)
		(layer "F.Cu")
		(net "M_A_CPU0_SB_CA<3>")
	)
	(segment
		(start 331.799946 -246.626126)
		(end 331.482954 -246.626126)
		(width 0.1016)
		(layer "F.Cu")
		(net "M_A_CPU0_SB_CA<3>")
	)
	(segment
		(start 315.713618 -251.17552)
		(end 315.072776 -250.91009)
		(width 0.20066)
		(layer "F.Cu")
		(net "M_A_CPU0_SB_CA<3>")
	)
	(segment
		(start 322.63842 -248.720864)
		(end 320.183764 -251.17552)
		(width 0.20066)
		(layer "F.Cu")
		(net "M_A_CPU0_SB_CA<3>")
	)
	(segment
		(start 305.443382 -250.016772)
		(end 306.67198 -250.016772)
		(width 0.20066)
		(layer "F.Cu")
		(net "M_A_CPU0_SB_CA<3>")
	)
	(segment
		(start 312.005472 -250.41606)
		(end 312.40476 -250.016772)
		(width 0.20066)
		(layer "F.Cu")
		(net "M_A_CPU0_SB_CA<3>")
	)
	(segment
		(start 333.951072 -246.592344)
		(end 333.876396 -246.549164)
		(width 0.088646)
		(layer "F.Cu")
		(net "M_A_CPU0_SB_CA<3>")
	)
	(segment
		(start 311.602374 -250.41606)
		(end 312.005472 -250.41606)
		(width 0.20066)
		(layer "F.Cu")
		(net "M_A_CPU0_SB_CA<3>")
	)
	(segment
		(start 306.8193 -250.337828)
		(end 306.942744 -250.461272)
		(width 0.20066)
		(layer "F.Cu")
		(net "M_A_CPU0_SB_CA<3>")
	)
	(segment
		(start 331.482954 -246.626126)
		(end 329.702668 -248.406412)
		(width 0.1016)
		(layer "F.Cu")
		(net "M_A_CPU0_SB_CA<3>")
	)
	(segment
		(start 333.124556 -246.634254)
		(end 333.008478 -246.518176)
		(width 0.088646)
		(layer "F.Cu")
		(net "M_A_CPU0_SB_CA<3>")
	)
	(segment
		(start 310.01208 -250.441714)
		(end 310.088026 -250.441714)
		(width 0.101854)
		(layer "F.Cu")
		(net "M_A_CPU0_SB_CA<3>")
	)
	(segment
		(start 306.8193 -250.164092)
		(end 306.8193 -250.337828)
		(width 0.20066)
		(layer "F.Cu")
		(net "M_A_CPU0_SB_CA<3>")
	)
	(segment
		(start 314.727336 -250.766834)
		(end 313.977274 -250.016772)
		(width 0.20066)
		(layer "F.Cu")
		(net "M_A_CPU0_SB_CA<3>")
	)
	(segment
		(start 329.702668 -248.406412)
		(end 322.952872 -248.406412)
		(width 0.1016)
		(layer "F.Cu")
		(net "M_A_CPU0_SB_CA<3>")
	)
	(segment
		(start 333.008478 -246.518176)
		(end 331.907896 -246.518176)
		(width 0.088646)
		(layer "F.Cu")
		(net "M_A_CPU0_SB_CA<3>")
	)
	(segment
		(start 306.942744 -250.461272)
		(end 307.76291 -250.461272)
		(width 0.20066)
		(layer "F.Cu")
		(net "M_A_CPU0_SB_CA<3>")
	)
	(segment
		(start 312.40476 -250.016772)
		(end 312.987182 -250.016772)
		(width 0.20066)
		(layer "F.Cu")
		(net "M_A_CPU0_SB_CA<3>")
	)
	(segment
		(start 313.977274 -250.016772)
		(end 312.987182 -250.016772)
		(width 0.20066)
		(layer "F.Cu")
		(net "M_A_CPU0_SB_CA<3>")
	)
	(segment
		(start 306.67198 -250.016772)
		(end 306.8193 -250.164092)
		(width 0.20066)
		(layer "F.Cu")
		(net "M_A_CPU0_SB_CA<3>")
	)
	(segment
		(start 310.374792 -250.441714)
		(end 310.730646 -250.08586)
		(width 0.20066)
		(layer "F.Cu")
		(net "M_A_CPU0_SB_CA<3>")
	)
	(segment
		(start 320.183764 -251.17552)
		(end 315.713618 -251.17552)
		(width 0.20066)
		(layer "F.Cu")
		(net "M_A_CPU0_SB_CA<3>")
	)
	(segment
		(start 322.952872 -248.406412)
		(end 322.63842 -248.720864)
		(width 0.1016)
		(layer "F.Cu")
		(net "M_A_CPU0_SB_CA<3>")
	)
	(segment
		(start 310.730646 -250.08586)
		(end 311.272174 -250.08586)
		(width 0.20066)
		(layer "F.Cu")
		(net "M_A_CPU0_SB_CA<3>")
	)
	(segment
		(start 333.502254 -246.549164)
		(end 333.425292 -246.59336)
		(width 0.088646)
		(layer "F.Cu")
		(net "M_A_CPU0_SB_CA<3>")
	)
	(segment
		(start 310.088026 -250.441714)
		(end 310.374792 -250.441714)
		(width 0.20066)
		(layer "F.Cu")
		(net "M_A_CPU0_SB_CA<3>")
	)
	(segment
		(start 307.76291 -250.461272)
		(end 307.808122 -250.461272)
		(width 0.101854)
		(layer "F.Cu")
		(net "M_A_CPU0_SB_CA<3>")
	)
	(segment
		(start 331.848714 -246.577358)
		(end 331.799946 -246.626126)
		(width 0.1016)
		(layer "F.Cu")
		(net "M_A_CPU0_SB_CA<3>")
	)
	(arc
		(start 333.876396 -246.549164)
		(mid 333.689342 -246.49908)
		(end 333.502254 -246.549164)
		(width 0.088646)
		(layer "F.Cu")
		(net "M_A_CPU0_SB_CA<3>")
	)
	(arc
		(start 333.425292 -246.59336)
		(mid 333.278934 -246.643225)
		(end 333.124556 -246.634254)
		(width 0.088646)
		(layer "F.Cu")
		(net "M_A_CPU0_SB_CA<3>")
	)
	(segment
		(start 304.354484 -251.310394)
		(end 304.37328 -251.291598)
		(width 0.101854)
		(layer "F.Cu")
		(net "M_A_CPU0_SB_CA<2>")
	)
	(segment
		(start 302.21428 -250.866656)
		(end 303.113948 -251.766324)
		(width 0.20066)
		(layer "F.Cu")
		(net "M_A_CPU0_SB_CA<2>")
	)
	(segment
		(start 307.048154 -251.291598)
		(end 307.473096 -250.866656)
		(width 0.20066)
		(layer "F.Cu")
		(net "M_A_CPU0_SB_CA<2>")
	)
	(segment
		(start 307.473096 -250.866656)
		(end 308.887114 -250.866656)
		(width 0.20066)
		(layer "F.Cu")
		(net "M_A_CPU0_SB_CA<2>")
	)
	(segment
		(start 333.012542 -247.207786)
		(end 332.87335 -247.288812)
		(width 0.088646)
		(layer "F.Cu")
		(net "M_A_CPU0_SB_CA<2>")
	)
	(segment
		(start 323.33692 -248.936764)
		(end 320.356992 -251.916692)
		(width 0.20066)
		(layer "F.Cu")
		(net "M_A_CPU0_SB_CA<2>")
	)
	(segment
		(start 304.37328 -251.291598)
		(end 306.60848 -251.291598)
		(width 0.1016)
		(layer "F.Cu")
		(net "M_A_CPU0_SB_CA<2>")
	)
	(segment
		(start 323.562472 -248.711212)
		(end 323.33692 -248.936764)
		(width 0.1016)
		(layer "F.Cu")
		(net "M_A_CPU0_SB_CA<2>")
	)
	(segment
		(start 303.922176 -251.310394)
		(end 304.319178 -251.310394)
		(width 0.20066)
		(layer "F.Cu")
		(net "M_A_CPU0_SB_CA<2>")
	)
	(segment
		(start 310.934608 -250.866656)
		(end 308.887114 -250.866656)
		(width 0.20066)
		(layer "F.Cu")
		(net "M_A_CPU0_SB_CA<2>")
	)
	(segment
		(start 311.879234 -251.313188)
		(end 311.84088 -251.313188)
		(width 0.101854)
		(layer "F.Cu")
		(net "M_A_CPU0_SB_CA<2>")
	)
	(segment
		(start 330.990956 -248.711212)
		(end 323.562472 -248.711212)
		(width 0.1016)
		(layer "F.Cu")
		(net "M_A_CPU0_SB_CA<2>")
	)
	(segment
		(start 332.102968 -247.5992)
		(end 331.877162 -247.825006)
		(width 0.088646)
		(layer "F.Cu")
		(net "M_A_CPU0_SB_CA<2>")
	)
	(segment
		(start 332.562962 -247.5992)
		(end 332.102968 -247.5992)
		(width 0.088646)
		(layer "F.Cu")
		(net "M_A_CPU0_SB_CA<2>")
	)
	(segment
		(start 311.900824 -251.291598)
		(end 311.879234 -251.313188)
		(width 0.101854)
		(layer "F.Cu")
		(net "M_A_CPU0_SB_CA<2>")
	)
	(segment
		(start 306.644294 -251.291598)
		(end 307.048154 -251.291598)
		(width 0.20066)
		(layer "F.Cu")
		(net "M_A_CPU0_SB_CA<2>")
	)
	(segment
		(start 314.17768 -251.291598)
		(end 311.900824 -251.291598)
		(width 0.1016)
		(layer "F.Cu")
		(net "M_A_CPU0_SB_CA<2>")
	)
	(segment
		(start 311.84088 -251.313188)
		(end 311.38114 -251.313188)
		(width 0.20066)
		(layer "F.Cu")
		(net "M_A_CPU0_SB_CA<2>")
	)
	(segment
		(start 332.87335 -247.288812)
		(end 332.562962 -247.5992)
		(width 0.088646)
		(layer "F.Cu")
		(net "M_A_CPU0_SB_CA<2>")
	)
	(segment
		(start 314.33008 -251.291598)
		(end 314.17768 -251.291598)
		(width 0.20066)
		(layer "F.Cu")
		(net "M_A_CPU0_SB_CA<2>")
	)
	(segment
		(start 303.466246 -251.766324)
		(end 303.922176 -251.310394)
		(width 0.20066)
		(layer "F.Cu")
		(net "M_A_CPU0_SB_CA<2>")
	)
	(segment
		(start 333.735934 -246.900446)
		(end 333.012542 -247.207786)
		(width 0.088646)
		(layer "F.Cu")
		(net "M_A_CPU0_SB_CA<2>")
	)
	(segment
		(start 314.955174 -251.916692)
		(end 314.33008 -251.291598)
		(width 0.20066)
		(layer "F.Cu")
		(net "M_A_CPU0_SB_CA<2>")
	)
	(segment
		(start 331.877162 -247.825006)
		(end 330.990956 -248.711212)
		(width 0.1016)
		(layer "F.Cu")
		(net "M_A_CPU0_SB_CA<2>")
	)
	(segment
		(start 304.319178 -251.310394)
		(end 304.354484 -251.310394)
		(width 0.101854)
		(layer "F.Cu")
		(net "M_A_CPU0_SB_CA<2>")
	)
	(segment
		(start 320.356992 -251.916692)
		(end 314.955174 -251.916692)
		(width 0.20066)
		(layer "F.Cu")
		(net "M_A_CPU0_SB_CA<2>")
	)
	(segment
		(start 301.343314 -250.866656)
		(end 302.21428 -250.866656)
		(width 0.20066)
		(layer "F.Cu")
		(net "M_A_CPU0_SB_CA<2>")
	)
	(segment
		(start 311.38114 -251.313188)
		(end 310.934608 -250.866656)
		(width 0.20066)
		(layer "F.Cu")
		(net "M_A_CPU0_SB_CA<2>")
	)
	(segment
		(start 303.113948 -251.766324)
		(end 303.466246 -251.766324)
		(width 0.20066)
		(layer "F.Cu")
		(net "M_A_CPU0_SB_CA<2>")
	)
	(segment
		(start 306.60848 -251.291598)
		(end 306.644294 -251.291598)
		(width 0.101854)
		(layer "F.Cu")
		(net "M_A_CPU0_SB_CA<2>")
	)
	(segment
		(start 334.018636 -248.03862)
		(end 334.008222 -248.032524)
		(width 0.088646)
		(layer "F.Cu")
		(net "M_A_CPU0_SB_CA<1>")
	)
	(segment
		(start 311.913524 -251.962412)
		(end 312.159142 -251.716794)
		(width 0.20066)
		(layer "F.Cu")
		(net "M_A_CPU0_SB_CA<1>")
	)
	(segment
		(start 311.083198 -251.62891)
		(end 311.4167 -251.962412)
		(width 0.20066)
		(layer "F.Cu")
		(net "M_A_CPU0_SB_CA<1>")
	)
	(segment
		(start 310.088026 -252.141736)
		(end 310.39308 -252.141736)
		(width 0.20066)
		(layer "F.Cu")
		(net "M_A_CPU0_SB_CA<1>")
	)
	(segment
		(start 335.14538 -248.46788)
		(end 334.825086 -248.147586)
		(width 0.088646)
		(layer "F.Cu")
		(net "M_A_CPU0_SB_CA<1>")
	)
	(segment
		(start 310.57342 -251.961396)
		(end 310.57342 -251.80925)
		(width 0.20066)
		(layer "F.Cu")
		(net "M_A_CPU0_SB_CA<1>")
	)
	(segment
		(start 310.57342 -251.80925)
		(end 310.75376 -251.62891)
		(width 0.20066)
		(layer "F.Cu")
		(net "M_A_CPU0_SB_CA<1>")
	)
	(segment
		(start 331.690218 -249.016012)
		(end 324.214236 -249.016012)
		(width 0.1016)
		(layer "F.Cu")
		(net "M_A_CPU0_SB_CA<1>")
	)
	(segment
		(start 332.798928 -249.016012)
		(end 331.690218 -249.016012)
		(width 0.088646)
		(layer "F.Cu")
		(net "M_A_CPU0_SB_CA<1>")
	)
	(segment
		(start 324.005702 -249.224546)
		(end 320.621914 -252.608334)
		(width 0.20066)
		(layer "F.Cu")
		(net "M_A_CPU0_SB_CA<1>")
	)
	(segment
		(start 320.621914 -252.608334)
		(end 314.726574 -252.608334)
		(width 0.20066)
		(layer "F.Cu")
		(net "M_A_CPU0_SB_CA<1>")
	)
	(segment
		(start 310.75376 -251.62891)
		(end 311.083198 -251.62891)
		(width 0.20066)
		(layer "F.Cu")
		(net "M_A_CPU0_SB_CA<1>")
	)
	(segment
		(start 333.165704 -248.227088)
		(end 333.165704 -248.649236)
		(width 0.088646)
		(layer "F.Cu")
		(net "M_A_CPU0_SB_CA<1>")
	)
	(segment
		(start 311.4167 -251.962412)
		(end 311.913524 -251.962412)
		(width 0.20066)
		(layer "F.Cu")
		(net "M_A_CPU0_SB_CA<1>")
	)
	(segment
		(start 334.825086 -248.147586)
		(end 334.425544 -248.147586)
		(width 0.088646)
		(layer "F.Cu")
		(net "M_A_CPU0_SB_CA<1>")
	)
	(segment
		(start 310.39308 -252.141736)
		(end 310.57342 -251.961396)
		(width 0.20066)
		(layer "F.Cu")
		(net "M_A_CPU0_SB_CA<1>")
	)
	(segment
		(start 307.127402 -251.716794)
		(end 307.571902 -252.161294)
		(width 0.20066)
		(layer "F.Cu")
		(net "M_A_CPU0_SB_CA<1>")
	)
	(segment
		(start 313.835034 -251.716794)
		(end 312.987182 -251.716794)
		(width 0.20066)
		(layer "F.Cu")
		(net "M_A_CPU0_SB_CA<1>")
	)
	(segment
		(start 324.214236 -249.016012)
		(end 324.005702 -249.224546)
		(width 0.1016)
		(layer "F.Cu")
		(net "M_A_CPU0_SB_CA<1>")
	)
	(segment
		(start 333.27848 -248.114312)
		(end 333.165704 -248.227088)
		(width 0.088646)
		(layer "F.Cu")
		(net "M_A_CPU0_SB_CA<1>")
	)
	(segment
		(start 333.165704 -248.649236)
		(end 332.798928 -249.016012)
		(width 0.088646)
		(layer "F.Cu")
		(net "M_A_CPU0_SB_CA<1>")
	)
	(segment
		(start 314.726574 -252.608334)
		(end 313.835034 -251.716794)
		(width 0.20066)
		(layer "F.Cu")
		(net "M_A_CPU0_SB_CA<1>")
	)
	(segment
		(start 335.14538 -249.342148)
		(end 335.14538 -248.46788)
		(width 0.088646)
		(layer "F.Cu")
		(net "M_A_CPU0_SB_CA<1>")
	)
	(segment
		(start 307.782722 -252.161294)
		(end 307.80228 -252.141736)
		(width 0.101854)
		(layer "F.Cu")
		(net "M_A_CPU0_SB_CA<1>")
	)
	(segment
		(start 305.443382 -251.716794)
		(end 307.127402 -251.716794)
		(width 0.20066)
		(layer "F.Cu")
		(net "M_A_CPU0_SB_CA<1>")
	)
	(segment
		(start 310.03748 -252.141736)
		(end 310.088026 -252.141736)
		(width 0.101854)
		(layer "F.Cu")
		(net "M_A_CPU0_SB_CA<1>")
	)
	(segment
		(start 312.159142 -251.716794)
		(end 312.987182 -251.716794)
		(width 0.20066)
		(layer "F.Cu")
		(net "M_A_CPU0_SB_CA<1>")
	)
	(segment
		(start 307.76291 -252.161294)
		(end 307.782722 -252.161294)
		(width 0.101854)
		(layer "F.Cu")
		(net "M_A_CPU0_SB_CA<1>")
	)
	(segment
		(start 307.571902 -252.161294)
		(end 307.76291 -252.161294)
		(width 0.20066)
		(layer "F.Cu")
		(net "M_A_CPU0_SB_CA<1>")
	)
	(segment
		(start 307.80228 -252.141736)
		(end 310.03748 -252.141736)
		(width 0.1016)
		(layer "F.Cu")
		(net "M_A_CPU0_SB_CA<1>")
	)
	(arc
		(start 333.452978 -248.03862)
		(mid 333.367891 -248.08145)
		(end 333.27848 -248.114312)
		(width 0.088646)
		(layer "F.Cu")
		(net "M_A_CPU0_SB_CA<1>")
	)
	(arc
		(start 334.425544 -248.147586)
		(mid 334.214929 -248.11986)
		(end 334.018636 -248.03862)
		(width 0.088646)
		(layer "F.Cu")
		(net "M_A_CPU0_SB_CA<1>")
	)
	(arc
		(start 334.008222 -248.032524)
		(mid 333.72979 -247.962678)
		(end 333.452978 -248.03862)
		(width 0.088646)
		(layer "F.Cu")
		(net "M_A_CPU0_SB_CA<1>")
	)
	(segment
		(start 303.866042 -252.115574)
		(end 304.319178 -252.115574)
		(width 0.20066)
		(layer "F.Cu")
		(net "M_A_CPU0_SB_CA<0>")
	)
	(segment
		(start 304.319178 -252.115574)
		(end 304.347118 -252.115574)
		(width 0.101854)
		(layer "F.Cu")
		(net "M_A_CPU0_SB_CA<0>")
	)
	(segment
		(start 331.842618 -249.321066)
		(end 324.816978 -249.321066)
		(width 0.1016)
		(layer "F.Cu")
		(net "M_A_CPU0_SB_CA<0>")
	)
	(segment
		(start 314.001404 -253.193296)
		(end 310.63438 -253.193296)
		(width 0.20066)
		(layer "F.Cu")
		(net "M_A_CPU0_SB_CA<0>")
	)
	(segment
		(start 333.487268 -248.261124)
		(end 333.364586 -248.383806)
		(width 0.088646)
		(layer "F.Cu")
		(net "M_A_CPU0_SB_CA<0>")
	)
	(segment
		(start 303.351184 -252.854968)
		(end 303.66208 -252.544072)
		(width 0.20066)
		(layer "F.Cu")
		(net "M_A_CPU0_SB_CA<0>")
	)
	(segment
		(start 310.63438 -253.193296)
		(end 310.007762 -252.566678)
		(width 0.20066)
		(layer "F.Cu")
		(net "M_A_CPU0_SB_CA<0>")
	)
	(segment
		(start 303.66208 -252.319536)
		(end 303.866042 -252.115574)
		(width 0.20066)
		(layer "F.Cu")
		(net "M_A_CPU0_SB_CA<0>")
	)
	(segment
		(start 332.764638 -249.321066)
		(end 331.842618 -249.321066)
		(width 0.088646)
		(layer "F.Cu")
		(net "M_A_CPU0_SB_CA<0>")
	)
	(segment
		(start 302.694086 -252.566678)
		(end 302.982376 -252.854968)
		(width 0.20066)
		(layer "F.Cu")
		(net "M_A_CPU0_SB_CA<0>")
	)
	(segment
		(start 304.347118 -252.115574)
		(end 304.37328 -252.141736)
		(width 0.101854)
		(layer "F.Cu")
		(net "M_A_CPU0_SB_CA<0>")
	)
	(segment
		(start 303.66208 -252.544072)
		(end 303.66208 -252.319536)
		(width 0.20066)
		(layer "F.Cu")
		(net "M_A_CPU0_SB_CA<0>")
	)
	(segment
		(start 304.37328 -252.141736)
		(end 306.58308 -252.141736)
		(width 0.1016)
		(layer "F.Cu")
		(net "M_A_CPU0_SB_CA<0>")
	)
	(segment
		(start 334.320642 -248.433082)
		(end 333.922878 -248.20372)
		(width 0.088646)
		(layer "F.Cu")
		(net "M_A_CPU0_SB_CA<0>")
	)
	(segment
		(start 306.644294 -252.141736)
		(end 306.744878 -252.141736)
		(width 0.20066)
		(layer "F.Cu")
		(net "M_A_CPU0_SB_CA<0>")
	)
	(segment
		(start 301.343314 -252.566678)
		(end 302.694086 -252.566678)
		(width 0.20066)
		(layer "F.Cu")
		(net "M_A_CPU0_SB_CA<0>")
	)
	(segment
		(start 306.58308 -252.141736)
		(end 306.644294 -252.141736)
		(width 0.101854)
		(layer "F.Cu")
		(net "M_A_CPU0_SB_CA<0>")
	)
	(segment
		(start 314.411868 -253.60376)
		(end 314.001404 -253.193296)
		(width 0.20066)
		(layer "F.Cu")
		(net "M_A_CPU0_SB_CA<0>")
	)
	(segment
		(start 333.364586 -248.383806)
		(end 333.364586 -248.721118)
		(width 0.088646)
		(layer "F.Cu")
		(net "M_A_CPU0_SB_CA<0>")
	)
	(segment
		(start 324.816978 -249.321066)
		(end 324.5231 -249.614944)
		(width 0.1016)
		(layer "F.Cu")
		(net "M_A_CPU0_SB_CA<0>")
	)
	(segment
		(start 302.982376 -252.854968)
		(end 303.351184 -252.854968)
		(width 0.20066)
		(layer "F.Cu")
		(net "M_A_CPU0_SB_CA<0>")
	)
	(segment
		(start 307.16982 -252.566678)
		(end 308.887114 -252.566678)
		(width 0.20066)
		(layer "F.Cu")
		(net "M_A_CPU0_SB_CA<0>")
	)
	(segment
		(start 324.5231 -249.614944)
		(end 320.534284 -253.60376)
		(width 0.20066)
		(layer "F.Cu")
		(net "M_A_CPU0_SB_CA<0>")
	)
	(segment
		(start 333.364586 -248.721118)
		(end 332.764638 -249.321066)
		(width 0.088646)
		(layer "F.Cu")
		(net "M_A_CPU0_SB_CA<0>")
	)
	(segment
		(start 310.007762 -252.566678)
		(end 308.887114 -252.566678)
		(width 0.20066)
		(layer "F.Cu")
		(net "M_A_CPU0_SB_CA<0>")
	)
	(segment
		(start 320.534284 -253.60376)
		(end 314.411868 -253.60376)
		(width 0.20066)
		(layer "F.Cu")
		(net "M_A_CPU0_SB_CA<0>")
	)
	(segment
		(start 306.744878 -252.141736)
		(end 307.16982 -252.566678)
		(width 0.20066)
		(layer "F.Cu")
		(net "M_A_CPU0_SB_CA<0>")
	)
	(arc
		(start 334.675734 -248.528078)
		(mid 334.491948 -248.503912)
		(end 334.320642 -248.433082)
		(width 0.088646)
		(layer "F.Cu")
		(net "M_A_CPU0_SB_CA<0>")
	)
	(arc
		(start 333.922878 -248.20372)
		(mid 333.695348 -248.158506)
		(end 333.487268 -248.261124)
		(width 0.088646)
		(layer "F.Cu")
		(net "M_A_CPU0_SB_CA<0>")
	)
	(segment
		(start 309.992014 -244.066568)
		(end 308.887114 -244.066568)
		(width 0.20066)
		(layer "F.Cu")
		(net "M_A_CPU0_SA_RSP<1>")
	)
	(segment
		(start 349.712534 -248.528078)
		(end 349.712534 -247.992392)
		(width 0.20066)
		(layer "F.Cu")
		(net "M_A_CPU0_SA_RSP<1>")
	)
	(segment
		(start 349.712534 -247.992392)
		(end 349.71228 -247.992138)
		(width 0.20066)
		(layer "F.Cu")
		(net "M_A_CPU0_SA_RSP<1>")
	)
	(segment
		(start 344.271346 -247.673876)
		(end 344.260932 -247.66778)
		(width 0.088646)
		(layer "In6.Cu")
		(net "M_A_CPU0_SA_RSP<1>")
	)
	(segment
		(start 346.150946 -247.673876)
		(end 346.140532 -247.66778)
		(width 0.088646)
		(layer "In6.Cu")
		(net "M_A_CPU0_SA_RSP<1>")
	)
	(segment
		(start 347.651578 -247.664224)
		(end 347.645482 -247.66778)
		(width 0.088646)
		(layer "In6.Cu")
		(net "M_A_CPU0_SA_RSP<1>")
	)
	(segment
		(start 331.795882 -248.308368)
		(end 331.460602 -248.308368)
		(width 0.088646)
		(layer "In6.Cu")
		(net "M_A_CPU0_SA_RSP<1>")
	)
	(segment
		(start 345.766136 -247.66778)
		(end 345.755722 -247.673876)
		(width 0.088646)
		(layer "In6.Cu")
		(net "M_A_CPU0_SA_RSP<1>")
	)
	(segment
		(start 336.367882 -247.66778)
		(end 336.357468 -247.673876)
		(width 0.088646)
		(layer "In6.Cu")
		(net "M_A_CPU0_SA_RSP<1>")
	)
	(segment
		(start 310.99506 -245.069614)
		(end 309.992014 -244.066568)
		(width 0.18288)
		(layer "In6.Cu")
		(net "M_A_CPU0_SA_RSP<1>")
	)
	(segment
		(start 332.058264 -248.199656)
		(end 331.795882 -248.308368)
		(width 0.088646)
		(layer "In6.Cu")
		(net "M_A_CPU0_SA_RSP<1>")
	)
	(segment
		(start 347.645482 -247.66778)
		(end 347.63075 -247.676416)
		(width 0.088646)
		(layer "In6.Cu")
		(net "M_A_CPU0_SA_RSP<1>")
	)
	(segment
		(start 331.460602 -248.308368)
		(end 329.655424 -248.308368)
		(width 0.18288)
		(layer "In6.Cu")
		(net "M_A_CPU0_SA_RSP<1>")
	)
	(segment
		(start 349.868744 -247.72112)
		(end 349.844614 -247.631966)
		(width 0.088646)
		(layer "In6.Cu")
		(net "M_A_CPU0_SA_RSP<1>")
	)
	(segment
		(start 348.115636 -246.853964)
		(end 348.106746 -246.859044)
		(width 0.088646)
		(layer "In6.Cu")
		(net "M_A_CPU0_SA_RSP<1>")
	)
	(segment
		(start 337.692746 -247.673876)
		(end 337.682332 -247.66778)
		(width 0.088646)
		(layer "In6.Cu")
		(net "M_A_CPU0_SA_RSP<1>")
	)
	(segment
		(start 339.187536 -247.66778)
		(end 339.177122 -247.673876)
		(width 0.088646)
		(layer "In6.Cu")
		(net "M_A_CPU0_SA_RSP<1>")
	)
	(segment
		(start 349.617284 -247.193816)
		(end 349.617284 -247.178322)
		(width 0.088646)
		(layer "In6.Cu")
		(net "M_A_CPU0_SA_RSP<1>")
	)
	(segment
		(start 337.307936 -247.66778)
		(end 337.297522 -247.673876)
		(width 0.088646)
		(layer "In6.Cu")
		(net "M_A_CPU0_SA_RSP<1>")
	)
	(segment
		(start 343.886536 -247.66778)
		(end 343.876122 -247.673876)
		(width 0.088646)
		(layer "In6.Cu")
		(net "M_A_CPU0_SA_RSP<1>")
	)
	(segment
		(start 329.655424 -248.308368)
		(end 328.048874 -246.701818)
		(width 0.18288)
		(layer "In6.Cu")
		(net "M_A_CPU0_SA_RSP<1>")
	)
	(segment
		(start 317.395606 -248.331736)
		(end 314.133484 -245.069614)
		(width 0.18288)
		(layer "In6.Cu")
		(net "M_A_CPU0_SA_RSP<1>")
	)
	(segment
		(start 320.472308 -248.331736)
		(end 317.395606 -248.331736)
		(width 0.18288)
		(layer "In6.Cu")
		(net "M_A_CPU0_SA_RSP<1>")
	)
	(segment
		(start 341.066882 -247.66778)
		(end 341.05215 -247.676416)
		(width 0.088646)
		(layer "In6.Cu")
		(net "M_A_CPU0_SA_RSP<1>")
	)
	(segment
		(start 314.133484 -245.069614)
		(end 310.99506 -245.069614)
		(width 0.18288)
		(layer "In6.Cu")
		(net "M_A_CPU0_SA_RSP<1>")
	)
	(segment
		(start 342.946482 -247.66778)
		(end 342.93175 -247.676416)
		(width 0.088646)
		(layer "In6.Cu")
		(net "M_A_CPU0_SA_RSP<1>")
	)
	(segment
		(start 339.572346 -247.673876)
		(end 339.561932 -247.66778)
		(width 0.088646)
		(layer "In6.Cu")
		(net "M_A_CPU0_SA_RSP<1>")
	)
	(segment
		(start 342.006682 -247.66778)
		(end 341.99195 -247.676416)
		(width 0.088646)
		(layer "In6.Cu")
		(net "M_A_CPU0_SA_RSP<1>")
	)
	(segment
		(start 332.530958 -247.726962)
		(end 332.058264 -248.199656)
		(width 0.088646)
		(layer "In6.Cu")
		(net "M_A_CPU0_SA_RSP<1>")
	)
	(segment
		(start 328.048874 -246.701818)
		(end 322.102226 -246.701818)
		(width 0.18288)
		(layer "In6.Cu")
		(net "M_A_CPU0_SA_RSP<1>")
	)
	(segment
		(start 322.102226 -246.701818)
		(end 320.472308 -248.331736)
		(width 0.18288)
		(layer "In6.Cu")
		(net "M_A_CPU0_SA_RSP<1>")
	)
	(segment
		(start 349.438722 -246.859044)
		(end 349.429832 -246.853964)
		(width 0.088646)
		(layer "In6.Cu")
		(net "M_A_CPU0_SA_RSP<1>")
	)
	(segment
		(start 349.71228 -247.992138)
		(end 349.868744 -247.72112)
		(width 0.088646)
		(layer "In6.Cu")
		(net "M_A_CPU0_SA_RSP<1>")
	)
	(arc
		(start 340.127082 -247.66778)
		(mid 339.850523 -247.743523)
		(end 339.572346 -247.673876)
		(width 0.088646)
		(layer "In6.Cu")
		(net "M_A_CPU0_SA_RSP<1>")
	)
	(arc
		(start 341.05215 -247.676416)
		(mid 340.775675 -247.743736)
		(end 340.501478 -247.66778)
		(width 0.088646)
		(layer "In6.Cu")
		(net "M_A_CPU0_SA_RSP<1>")
	)
	(arc
		(start 346.140532 -247.66778)
		(mid 345.953334 -247.617637)
		(end 345.766136 -247.66778)
		(width 0.088646)
		(layer "In6.Cu")
		(net "M_A_CPU0_SA_RSP<1>")
	)
	(arc
		(start 347.63075 -247.676416)
		(mid 347.354275 -247.743736)
		(end 347.080078 -247.66778)
		(width 0.088646)
		(layer "In6.Cu")
		(net "M_A_CPU0_SA_RSP<1>")
	)
	(arc
		(start 346.705682 -247.66778)
		(mid 346.429123 -247.743523)
		(end 346.150946 -247.673876)
		(width 0.088646)
		(layer "In6.Cu")
		(net "M_A_CPU0_SA_RSP<1>")
	)
	(arc
		(start 349.055436 -246.853964)
		(mid 348.772734 -246.92974)
		(end 348.490032 -246.853964)
		(width 0.088646)
		(layer "In6.Cu")
		(net "M_A_CPU0_SA_RSP<1>")
	)
	(arc
		(start 345.755722 -247.673876)
		(mid 345.47729 -247.743722)
		(end 345.200478 -247.66778)
		(width 0.088646)
		(layer "In6.Cu")
		(net "M_A_CPU0_SA_RSP<1>")
	)
	(arc
		(start 333.548736 -247.66778)
		(mid 333.266034 -247.743556)
		(end 332.983332 -247.66778)
		(width 0.088646)
		(layer "In6.Cu")
		(net "M_A_CPU0_SA_RSP<1>")
	)
	(arc
		(start 349.617284 -247.178322)
		(mid 349.569605 -246.995422)
		(end 349.438722 -246.859044)
		(width 0.088646)
		(layer "In6.Cu")
		(net "M_A_CPU0_SA_RSP<1>")
	)
	(arc
		(start 337.682332 -247.66778)
		(mid 337.495134 -247.617637)
		(end 337.307936 -247.66778)
		(width 0.088646)
		(layer "In6.Cu")
		(net "M_A_CPU0_SA_RSP<1>")
	)
	(arc
		(start 347.928184 -247.178322)
		(mid 347.854193 -247.457888)
		(end 347.651578 -247.664224)
		(width 0.088646)
		(layer "In6.Cu")
		(net "M_A_CPU0_SA_RSP<1>")
	)
	(arc
		(start 338.621878 -247.66778)
		(mid 338.43468 -247.617637)
		(end 338.247482 -247.66778)
		(width 0.088646)
		(layer "In6.Cu")
		(net "M_A_CPU0_SA_RSP<1>")
	)
	(arc
		(start 339.177122 -247.673876)
		(mid 338.89869 -247.743722)
		(end 338.621878 -247.66778)
		(width 0.088646)
		(layer "In6.Cu")
		(net "M_A_CPU0_SA_RSP<1>")
	)
	(arc
		(start 332.983332 -247.66778)
		(mid 332.796134 -247.617637)
		(end 332.608936 -247.66778)
		(width 0.088646)
		(layer "In6.Cu")
		(net "M_A_CPU0_SA_RSP<1>")
	)
	(arc
		(start 349.429832 -246.853964)
		(mid 349.242634 -246.803821)
		(end 349.055436 -246.853964)
		(width 0.088646)
		(layer "In6.Cu")
		(net "M_A_CPU0_SA_RSP<1>")
	)
	(arc
		(start 336.357468 -247.673876)
		(mid 336.07929 -247.743599)
		(end 335.802732 -247.66778)
		(width 0.088646)
		(layer "In6.Cu")
		(net "M_A_CPU0_SA_RSP<1>")
	)
	(arc
		(start 339.561932 -247.66778)
		(mid 339.374734 -247.617637)
		(end 339.187536 -247.66778)
		(width 0.088646)
		(layer "In6.Cu")
		(net "M_A_CPU0_SA_RSP<1>")
	)
	(arc
		(start 333.923132 -247.66778)
		(mid 333.735934 -247.617637)
		(end 333.548736 -247.66778)
		(width 0.088646)
		(layer "In6.Cu")
		(net "M_A_CPU0_SA_RSP<1>")
	)
	(arc
		(start 338.247482 -247.66778)
		(mid 337.970923 -247.743523)
		(end 337.692746 -247.673876)
		(width 0.088646)
		(layer "In6.Cu")
		(net "M_A_CPU0_SA_RSP<1>")
	)
	(arc
		(start 335.428336 -247.66778)
		(mid 335.145634 -247.743556)
		(end 334.862932 -247.66778)
		(width 0.088646)
		(layer "In6.Cu")
		(net "M_A_CPU0_SA_RSP<1>")
	)
	(arc
		(start 342.381078 -247.66778)
		(mid 342.19388 -247.617637)
		(end 342.006682 -247.66778)
		(width 0.088646)
		(layer "In6.Cu")
		(net "M_A_CPU0_SA_RSP<1>")
	)
	(arc
		(start 344.826082 -247.66778)
		(mid 344.549523 -247.743523)
		(end 344.271346 -247.673876)
		(width 0.088646)
		(layer "In6.Cu")
		(net "M_A_CPU0_SA_RSP<1>")
	)
	(arc
		(start 337.297522 -247.673876)
		(mid 337.01909 -247.743722)
		(end 336.742278 -247.66778)
		(width 0.088646)
		(layer "In6.Cu")
		(net "M_A_CPU0_SA_RSP<1>")
	)
	(arc
		(start 334.862932 -247.66778)
		(mid 334.675734 -247.617637)
		(end 334.488536 -247.66778)
		(width 0.088646)
		(layer "In6.Cu")
		(net "M_A_CPU0_SA_RSP<1>")
	)
	(arc
		(start 336.742278 -247.66778)
		(mid 336.55508 -247.617637)
		(end 336.367882 -247.66778)
		(width 0.088646)
		(layer "In6.Cu")
		(net "M_A_CPU0_SA_RSP<1>")
	)
	(arc
		(start 348.106746 -246.859044)
		(mid 347.975832 -246.995404)
		(end 347.928184 -247.178322)
		(width 0.088646)
		(layer "In6.Cu")
		(net "M_A_CPU0_SA_RSP<1>")
	)
	(arc
		(start 342.93175 -247.676416)
		(mid 342.655275 -247.743736)
		(end 342.381078 -247.66778)
		(width 0.088646)
		(layer "In6.Cu")
		(net "M_A_CPU0_SA_RSP<1>")
	)
	(arc
		(start 344.260932 -247.66778)
		(mid 344.073734 -247.617637)
		(end 343.886536 -247.66778)
		(width 0.088646)
		(layer "In6.Cu")
		(net "M_A_CPU0_SA_RSP<1>")
	)
	(arc
		(start 334.488536 -247.66778)
		(mid 334.205834 -247.743556)
		(end 333.923132 -247.66778)
		(width 0.088646)
		(layer "In6.Cu")
		(net "M_A_CPU0_SA_RSP<1>")
	)
	(arc
		(start 341.99195 -247.676416)
		(mid 341.715475 -247.743736)
		(end 341.441278 -247.66778)
		(width 0.088646)
		(layer "In6.Cu")
		(net "M_A_CPU0_SA_RSP<1>")
	)
	(arc
		(start 343.876122 -247.673876)
		(mid 343.59769 -247.743722)
		(end 343.320878 -247.66778)
		(width 0.088646)
		(layer "In6.Cu")
		(net "M_A_CPU0_SA_RSP<1>")
	)
	(arc
		(start 335.802732 -247.66778)
		(mid 335.615534 -247.617637)
		(end 335.428336 -247.66778)
		(width 0.088646)
		(layer "In6.Cu")
		(net "M_A_CPU0_SA_RSP<1>")
	)
	(arc
		(start 340.501478 -247.66778)
		(mid 340.31428 -247.617637)
		(end 340.127082 -247.66778)
		(width 0.088646)
		(layer "In6.Cu")
		(net "M_A_CPU0_SA_RSP<1>")
	)
	(arc
		(start 348.490032 -246.853964)
		(mid 348.302834 -246.803821)
		(end 348.115636 -246.853964)
		(width 0.088646)
		(layer "In6.Cu")
		(net "M_A_CPU0_SA_RSP<1>")
	)
	(arc
		(start 349.844614 -247.631966)
		(mid 349.680582 -247.439017)
		(end 349.617284 -247.193816)
		(width 0.088646)
		(layer "In6.Cu")
		(net "M_A_CPU0_SA_RSP<1>")
	)
	(arc
		(start 345.200478 -247.66778)
		(mid 345.01328 -247.617637)
		(end 344.826082 -247.66778)
		(width 0.088646)
		(layer "In6.Cu")
		(net "M_A_CPU0_SA_RSP<1>")
	)
	(arc
		(start 341.441278 -247.66778)
		(mid 341.25408 -247.617637)
		(end 341.066882 -247.66778)
		(width 0.088646)
		(layer "In6.Cu")
		(net "M_A_CPU0_SA_RSP<1>")
	)
	(arc
		(start 347.080078 -247.66778)
		(mid 346.89288 -247.617637)
		(end 346.705682 -247.66778)
		(width 0.088646)
		(layer "In6.Cu")
		(net "M_A_CPU0_SA_RSP<1>")
	)
	(arc
		(start 343.320878 -247.66778)
		(mid 343.13368 -247.617637)
		(end 342.946482 -247.66778)
		(width 0.088646)
		(layer "In6.Cu")
		(net "M_A_CPU0_SA_RSP<1>")
	)
	(arc
		(start 332.608936 -247.66778)
		(mid 332.568006 -247.694813)
		(end 332.530958 -247.726962)
		(width 0.088646)
		(layer "In6.Cu")
		(net "M_A_CPU0_SA_RSP<1>")
	)
	(segment
		(start 349.241364 -247.179592)
		(end 349.242634 -247.178322)
		(width 0.20066)
		(layer "F.Cu")
		(net "M_A_CPU0_SA_RSP<0>")
	)
	(segment
		(start 349.241364 -247.713246)
		(end 349.241364 -247.179592)
		(width 0.20066)
		(layer "F.Cu")
		(net "M_A_CPU0_SA_RSP<0>")
	)
	(segment
		(start 302.448214 -244.066568)
		(end 301.343314 -244.066568)
		(width 0.20066)
		(layer "F.Cu")
		(net "M_A_CPU0_SA_RSP<0>")
	)
	(segment
		(start 349.24238 -247.714262)
		(end 349.241364 -247.713246)
		(width 0.20066)
		(layer "F.Cu")
		(net "M_A_CPU0_SA_RSP<0>")
	)
	(segment
		(start 341.066882 -248.316496)
		(end 341.05215 -248.30786)
		(width 0.088646)
		(layer "In6.Cu")
		(net "M_A_CPU0_SA_RSP<0>")
	)
	(segment
		(start 304.996596 -244.560598)
		(end 304.247042 -244.560598)
		(width 0.18288)
		(layer "In6.Cu")
		(net "M_A_CPU0_SA_RSP<0>")
	)
	(segment
		(start 302.529494 -243.985288)
		(end 302.448214 -244.066568)
		(width 0.18288)
		(layer "In6.Cu")
		(net "M_A_CPU0_SA_RSP<0>")
	)
	(segment
		(start 333.259176 -249.297444)
		(end 331.460602 -249.297444)
		(width 0.088646)
		(layer "In6.Cu")
		(net "M_A_CPU0_SA_RSP<0>")
	)
	(segment
		(start 313.659012 -246.342154)
		(end 313.1947 -245.877842)
		(width 0.18288)
		(layer "In6.Cu")
		(net "M_A_CPU0_SA_RSP<0>")
	)
	(segment
		(start 343.886536 -248.316496)
		(end 343.876122 -248.3104)
		(width 0.088646)
		(layer "In6.Cu")
		(net "M_A_CPU0_SA_RSP<0>")
	)
	(segment
		(start 345.766136 -248.316496)
		(end 345.755722 -248.3104)
		(width 0.088646)
		(layer "In6.Cu")
		(net "M_A_CPU0_SA_RSP<0>")
	)
	(segment
		(start 307.927756 -244.376448)
		(end 307.372512 -244.376448)
		(width 0.18288)
		(layer "In6.Cu")
		(net "M_A_CPU0_SA_RSP<0>")
	)
	(segment
		(start 330.161392 -249.297444)
		(end 327.90384 -247.039892)
		(width 0.18288)
		(layer "In6.Cu")
		(net "M_A_CPU0_SA_RSP<0>")
	)
	(segment
		(start 344.826082 -248.316496)
		(end 344.815668 -248.3104)
		(width 0.088646)
		(layer "In6.Cu")
		(net "M_A_CPU0_SA_RSP<0>")
	)
	(segment
		(start 320.505074 -249.003058)
		(end 317.157354 -249.003058)
		(width 0.18288)
		(layer "In6.Cu")
		(net "M_A_CPU0_SA_RSP<0>")
	)
	(segment
		(start 311.834022 -246.540782)
		(end 310.867806 -246.540782)
		(width 0.18288)
		(layer "In6.Cu")
		(net "M_A_CPU0_SA_RSP<0>")
	)
	(segment
		(start 333.336138 -249.220482)
		(end 333.259176 -249.297444)
		(width 0.088646)
		(layer "In6.Cu")
		(net "M_A_CPU0_SA_RSP<0>")
	)
	(segment
		(start 347.645482 -248.316496)
		(end 347.63075 -248.30786)
		(width 0.088646)
		(layer "In6.Cu")
		(net "M_A_CPU0_SA_RSP<0>")
	)
	(segment
		(start 310.237886 -245.910862)
		(end 308.659276 -245.910862)
		(width 0.18288)
		(layer "In6.Cu")
		(net "M_A_CPU0_SA_RSP<0>")
	)
	(segment
		(start 305.929792 -244.560598)
		(end 305.664616 -244.295422)
		(width 0.18288)
		(layer "In6.Cu")
		(net "M_A_CPU0_SA_RSP<0>")
	)
	(segment
		(start 307.188362 -244.560598)
		(end 305.929792 -244.560598)
		(width 0.18288)
		(layer "In6.Cu")
		(net "M_A_CPU0_SA_RSP<0>")
	)
	(segment
		(start 302.810418 -243.985288)
		(end 302.529494 -243.985288)
		(width 0.18288)
		(layer "In6.Cu")
		(net "M_A_CPU0_SA_RSP<0>")
	)
	(segment
		(start 337.307936 -248.316496)
		(end 337.297522 -248.3104)
		(width 0.088646)
		(layer "In6.Cu")
		(net "M_A_CPU0_SA_RSP<0>")
	)
	(segment
		(start 305.261772 -244.295422)
		(end 304.996596 -244.560598)
		(width 0.18288)
		(layer "In6.Cu")
		(net "M_A_CPU0_SA_RSP<0>")
	)
	(segment
		(start 334.401922 -249.125486)
		(end 334.393032 -249.130566)
		(width 0.088646)
		(layer "In6.Cu")
		(net "M_A_CPU0_SA_RSP<0>")
	)
	(segment
		(start 304.247042 -244.560598)
		(end 302.810418 -243.985288)
		(width 0.18288)
		(layer "In6.Cu")
		(net "M_A_CPU0_SA_RSP<0>")
	)
	(segment
		(start 342.006682 -248.316496)
		(end 341.99195 -248.30786)
		(width 0.088646)
		(layer "In6.Cu")
		(net "M_A_CPU0_SA_RSP<0>")
	)
	(segment
		(start 305.664616 -244.295422)
		(end 305.261772 -244.295422)
		(width 0.18288)
		(layer "In6.Cu")
		(net "M_A_CPU0_SA_RSP<0>")
	)
	(segment
		(start 340.127082 -248.316496)
		(end 340.116668 -248.3104)
		(width 0.088646)
		(layer "In6.Cu")
		(net "M_A_CPU0_SA_RSP<0>")
	)
	(segment
		(start 331.460602 -249.297444)
		(end 330.161392 -249.297444)
		(width 0.18288)
		(layer "In6.Cu")
		(net "M_A_CPU0_SA_RSP<0>")
	)
	(segment
		(start 336.367882 -248.316496)
		(end 336.357468 -248.3104)
		(width 0.088646)
		(layer "In6.Cu")
		(net "M_A_CPU0_SA_RSP<0>")
	)
	(segment
		(start 308.659276 -245.910862)
		(end 308.24932 -245.500906)
		(width 0.18288)
		(layer "In6.Cu")
		(net "M_A_CPU0_SA_RSP<0>")
	)
	(segment
		(start 313.1947 -245.877842)
		(end 312.496962 -245.877842)
		(width 0.18288)
		(layer "In6.Cu")
		(net "M_A_CPU0_SA_RSP<0>")
	)
	(segment
		(start 314.49645 -246.342154)
		(end 313.659012 -246.342154)
		(width 0.18288)
		(layer "In6.Cu")
		(net "M_A_CPU0_SA_RSP<0>")
	)
	(segment
		(start 348.483428 -247.710452)
		(end 348.384876 -247.809004)
		(width 0.088646)
		(layer "In6.Cu")
		(net "M_A_CPU0_SA_RSP<0>")
	)
	(segment
		(start 317.157354 -249.003058)
		(end 314.49645 -246.342154)
		(width 0.18288)
		(layer "In6.Cu")
		(net "M_A_CPU0_SA_RSP<0>")
	)
	(segment
		(start 349.242634 -247.178322)
		(end 348.551754 -247.65381)
		(width 0.088646)
		(layer "In6.Cu")
		(net "M_A_CPU0_SA_RSP<0>")
	)
	(segment
		(start 308.24932 -244.698012)
		(end 307.927756 -244.376448)
		(width 0.18288)
		(layer "In6.Cu")
		(net "M_A_CPU0_SA_RSP<0>")
	)
	(segment
		(start 339.187536 -248.316496)
		(end 339.177122 -248.3104)
		(width 0.088646)
		(layer "In6.Cu")
		(net "M_A_CPU0_SA_RSP<0>")
	)
	(segment
		(start 312.496962 -245.877842)
		(end 311.834022 -246.540782)
		(width 0.18288)
		(layer "In6.Cu")
		(net "M_A_CPU0_SA_RSP<0>")
	)
	(segment
		(start 333.467964 -249.12193)
		(end 333.453232 -249.130566)
		(width 0.088646)
		(layer "In6.Cu")
		(net "M_A_CPU0_SA_RSP<0>")
	)
	(segment
		(start 308.24932 -245.500906)
		(end 308.24932 -244.698012)
		(width 0.18288)
		(layer "In6.Cu")
		(net "M_A_CPU0_SA_RSP<0>")
	)
	(segment
		(start 338.247482 -248.316496)
		(end 338.237068 -248.3104)
		(width 0.088646)
		(layer "In6.Cu")
		(net "M_A_CPU0_SA_RSP<0>")
	)
	(segment
		(start 307.372512 -244.376448)
		(end 307.188362 -244.560598)
		(width 0.18288)
		(layer "In6.Cu")
		(net "M_A_CPU0_SA_RSP<0>")
	)
	(segment
		(start 346.705682 -248.316496)
		(end 346.695268 -248.3104)
		(width 0.088646)
		(layer "In6.Cu")
		(net "M_A_CPU0_SA_RSP<0>")
	)
	(segment
		(start 310.867806 -246.540782)
		(end 310.237886 -245.910862)
		(width 0.18288)
		(layer "In6.Cu")
		(net "M_A_CPU0_SA_RSP<0>")
	)
	(segment
		(start 327.90384 -247.039892)
		(end 322.46824 -247.039892)
		(width 0.18288)
		(layer "In6.Cu")
		(net "M_A_CPU0_SA_RSP<0>")
	)
	(segment
		(start 334.580484 -248.787666)
		(end 334.580484 -248.806208)
		(width 0.088646)
		(layer "In6.Cu")
		(net "M_A_CPU0_SA_RSP<0>")
	)
	(segment
		(start 322.46824 -247.039892)
		(end 320.505074 -249.003058)
		(width 0.18288)
		(layer "In6.Cu")
		(net "M_A_CPU0_SA_RSP<0>")
	)
	(arc
		(start 347.080078 -248.316496)
		(mid 346.89288 -248.366639)
		(end 346.705682 -248.316496)
		(width 0.088646)
		(layer "In6.Cu")
		(net "M_A_CPU0_SA_RSP<0>")
	)
	(arc
		(start 345.200478 -248.316496)
		(mid 345.01328 -248.366639)
		(end 344.826082 -248.316496)
		(width 0.088646)
		(layer "In6.Cu")
		(net "M_A_CPU0_SA_RSP<0>")
	)
	(arc
		(start 336.742278 -248.316496)
		(mid 336.55508 -248.366639)
		(end 336.367882 -248.316496)
		(width 0.088646)
		(layer "In6.Cu")
		(net "M_A_CPU0_SA_RSP<0>")
	)
	(arc
		(start 348.551754 -247.65381)
		(mid 348.516298 -247.680571)
		(end 348.483428 -247.710452)
		(width 0.088646)
		(layer "In6.Cu")
		(net "M_A_CPU0_SA_RSP<0>")
	)
	(arc
		(start 338.237068 -248.3104)
		(mid 337.95889 -248.240708)
		(end 337.682332 -248.316496)
		(width 0.088646)
		(layer "In6.Cu")
		(net "M_A_CPU0_SA_RSP<0>")
	)
	(arc
		(start 343.876122 -248.3104)
		(mid 343.59769 -248.240586)
		(end 343.320878 -248.316496)
		(width 0.088646)
		(layer "In6.Cu")
		(net "M_A_CPU0_SA_RSP<0>")
	)
	(arc
		(start 346.695268 -248.3104)
		(mid 346.41709 -248.240708)
		(end 346.140532 -248.316496)
		(width 0.088646)
		(layer "In6.Cu")
		(net "M_A_CPU0_SA_RSP<0>")
	)
	(arc
		(start 343.320878 -248.316496)
		(mid 343.13368 -248.366639)
		(end 342.946482 -248.316496)
		(width 0.088646)
		(layer "In6.Cu")
		(net "M_A_CPU0_SA_RSP<0>")
	)
	(arc
		(start 334.862932 -248.316496)
		(mid 334.660646 -248.515477)
		(end 334.580484 -248.787666)
		(width 0.088646)
		(layer "In6.Cu")
		(net "M_A_CPU0_SA_RSP<0>")
	)
	(arc
		(start 344.260932 -248.316496)
		(mid 344.073734 -248.366639)
		(end 343.886536 -248.316496)
		(width 0.088646)
		(layer "In6.Cu")
		(net "M_A_CPU0_SA_RSP<0>")
	)
	(arc
		(start 333.453232 -249.130566)
		(mid 333.391743 -249.171692)
		(end 333.336138 -249.220482)
		(width 0.088646)
		(layer "In6.Cu")
		(net "M_A_CPU0_SA_RSP<0>")
	)
	(arc
		(start 347.63075 -248.30786)
		(mid 347.354309 -248.240694)
		(end 347.080078 -248.316496)
		(width 0.088646)
		(layer "In6.Cu")
		(net "M_A_CPU0_SA_RSP<0>")
	)
	(arc
		(start 340.501478 -248.316496)
		(mid 340.31428 -248.366639)
		(end 340.127082 -248.316496)
		(width 0.088646)
		(layer "In6.Cu")
		(net "M_A_CPU0_SA_RSP<0>")
	)
	(arc
		(start 334.580484 -248.806208)
		(mid 334.532805 -248.989108)
		(end 334.401922 -249.125486)
		(width 0.088646)
		(layer "In6.Cu")
		(net "M_A_CPU0_SA_RSP<0>")
	)
	(arc
		(start 342.946482 -248.316496)
		(mid 342.66378 -248.240754)
		(end 342.381078 -248.316496)
		(width 0.088646)
		(layer "In6.Cu")
		(net "M_A_CPU0_SA_RSP<0>")
	)
	(arc
		(start 340.116668 -248.3104)
		(mid 339.83849 -248.240708)
		(end 339.561932 -248.316496)
		(width 0.088646)
		(layer "In6.Cu")
		(net "M_A_CPU0_SA_RSP<0>")
	)
	(arc
		(start 348.019878 -248.316496)
		(mid 347.83268 -248.366639)
		(end 347.645482 -248.316496)
		(width 0.088646)
		(layer "In6.Cu")
		(net "M_A_CPU0_SA_RSP<0>")
	)
	(arc
		(start 348.384876 -247.809004)
		(mid 348.356781 -247.843312)
		(end 348.335854 -247.88241)
		(width 0.088646)
		(layer "In6.Cu")
		(net "M_A_CPU0_SA_RSP<0>")
	)
	(arc
		(start 348.335854 -247.88241)
		(mid 348.223936 -248.132994)
		(end 348.019878 -248.316496)
		(width 0.088646)
		(layer "In6.Cu")
		(net "M_A_CPU0_SA_RSP<0>")
	)
	(arc
		(start 334.393032 -249.130566)
		(mid 334.205834 -249.180709)
		(end 334.018636 -249.130566)
		(width 0.088646)
		(layer "In6.Cu")
		(net "M_A_CPU0_SA_RSP<0>")
	)
	(arc
		(start 339.561932 -248.316496)
		(mid 339.374734 -248.366639)
		(end 339.187536 -248.316496)
		(width 0.088646)
		(layer "In6.Cu")
		(net "M_A_CPU0_SA_RSP<0>")
	)
	(arc
		(start 337.682332 -248.316496)
		(mid 337.495134 -248.366639)
		(end 337.307936 -248.316496)
		(width 0.088646)
		(layer "In6.Cu")
		(net "M_A_CPU0_SA_RSP<0>")
	)
	(arc
		(start 346.140532 -248.316496)
		(mid 345.953334 -248.366639)
		(end 345.766136 -248.316496)
		(width 0.088646)
		(layer "In6.Cu")
		(net "M_A_CPU0_SA_RSP<0>")
	)
	(arc
		(start 345.755722 -248.3104)
		(mid 345.47729 -248.240586)
		(end 345.200478 -248.316496)
		(width 0.088646)
		(layer "In6.Cu")
		(net "M_A_CPU0_SA_RSP<0>")
	)
	(arc
		(start 341.99195 -248.30786)
		(mid 341.715509 -248.240694)
		(end 341.441278 -248.316496)
		(width 0.088646)
		(layer "In6.Cu")
		(net "M_A_CPU0_SA_RSP<0>")
	)
	(arc
		(start 338.621878 -248.316496)
		(mid 338.43468 -248.366639)
		(end 338.247482 -248.316496)
		(width 0.088646)
		(layer "In6.Cu")
		(net "M_A_CPU0_SA_RSP<0>")
	)
	(arc
		(start 335.428336 -248.316496)
		(mid 335.145634 -248.240754)
		(end 334.862932 -248.316496)
		(width 0.088646)
		(layer "In6.Cu")
		(net "M_A_CPU0_SA_RSP<0>")
	)
	(arc
		(start 336.357468 -248.3104)
		(mid 336.07929 -248.240708)
		(end 335.802732 -248.316496)
		(width 0.088646)
		(layer "In6.Cu")
		(net "M_A_CPU0_SA_RSP<0>")
	)
	(arc
		(start 342.381078 -248.316496)
		(mid 342.19388 -248.366639)
		(end 342.006682 -248.316496)
		(width 0.088646)
		(layer "In6.Cu")
		(net "M_A_CPU0_SA_RSP<0>")
	)
	(arc
		(start 344.815668 -248.3104)
		(mid 344.53749 -248.240708)
		(end 344.260932 -248.316496)
		(width 0.088646)
		(layer "In6.Cu")
		(net "M_A_CPU0_SA_RSP<0>")
	)
	(arc
		(start 337.297522 -248.3104)
		(mid 337.01909 -248.240586)
		(end 336.742278 -248.316496)
		(width 0.088646)
		(layer "In6.Cu")
		(net "M_A_CPU0_SA_RSP<0>")
	)
	(arc
		(start 335.802732 -248.316496)
		(mid 335.615534 -248.366639)
		(end 335.428336 -248.316496)
		(width 0.088646)
		(layer "In6.Cu")
		(net "M_A_CPU0_SA_RSP<0>")
	)
	(arc
		(start 341.05215 -248.30786)
		(mid 340.775709 -248.240694)
		(end 340.501478 -248.316496)
		(width 0.088646)
		(layer "In6.Cu")
		(net "M_A_CPU0_SA_RSP<0>")
	)
	(arc
		(start 341.441278 -248.316496)
		(mid 341.25408 -248.366639)
		(end 341.066882 -248.316496)
		(width 0.088646)
		(layer "In6.Cu")
		(net "M_A_CPU0_SA_RSP<0>")
	)
	(arc
		(start 334.018636 -249.130566)
		(mid 333.744437 -249.054731)
		(end 333.467964 -249.12193)
		(width 0.088646)
		(layer "In6.Cu")
		(net "M_A_CPU0_SA_RSP<0>")
	)
	(arc
		(start 339.177122 -248.3104)
		(mid 338.89869 -248.240586)
		(end 338.621878 -248.316496)
		(width 0.088646)
		(layer "In6.Cu")
		(net "M_A_CPU0_SA_RSP<0>")
	)
	(segment
		(start 314.124086 -260.538214)
		(end 313.874658 -260.641592)
		(width 0.1016)
		(layer "F.Cu")
		(net "M_A_CPU0_SA_PAR")
	)
	(segment
		(start 331.113892 -255.011428)
		(end 329.809094 -256.316226)
		(width 0.1016)
		(layer "F.Cu")
		(net "M_A_CPU0_SA_PAR")
	)
	(segment
		(start 302.530002 -259.366766)
		(end 303.788318 -260.625082)
		(width 0.20066)
		(layer "F.Cu")
		(net "M_A_CPU0_SA_PAR")
	)
	(segment
		(start 332.476094 -253.649226)
		(end 331.113892 -255.011428)
		(width 0.088646)
		(layer "F.Cu")
		(net "M_A_CPU0_SA_PAR")
	)
	(segment
		(start 334.36433 -253.776226)
		(end 333.644494 -253.776226)
		(width 0.088646)
		(layer "F.Cu")
		(net "M_A_CPU0_SA_PAR")
	)
	(segment
		(start 314.917836 -260.209284)
		(end 314.555632 -260.359398)
		(width 0.20066)
		(layer "F.Cu")
		(net "M_A_CPU0_SA_PAR")
	)
	(segment
		(start 304.37328 -260.641592)
		(end 306.55768 -260.641592)
		(width 0.1016)
		(layer "F.Cu")
		(net "M_A_CPU0_SA_PAR")
	)
	(segment
		(start 314.12688 -260.536944)
		(end 314.124086 -260.538214)
		(width 0.101854)
		(layer "F.Cu")
		(net "M_A_CPU0_SA_PAR")
	)
	(segment
		(start 314.555632 -260.359398)
		(end 314.12688 -260.536944)
		(width 0.20066)
		(layer "F.Cu")
		(net "M_A_CPU0_SA_PAR")
	)
	(segment
		(start 311.953402 -260.625082)
		(end 311.91708 -260.625082)
		(width 0.101854)
		(layer "F.Cu")
		(net "M_A_CPU0_SA_PAR")
	)
	(segment
		(start 329.809094 -256.316226)
		(end 322.596764 -256.316226)
		(width 0.1016)
		(layer "F.Cu")
		(net "M_A_CPU0_SA_PAR")
	)
	(segment
		(start 316.772544 -258.354576)
		(end 314.917836 -260.209284)
		(width 0.20066)
		(layer "F.Cu")
		(net "M_A_CPU0_SA_PAR")
	)
	(segment
		(start 306.55768 -260.641592)
		(end 306.644294 -260.641592)
		(width 0.101854)
		(layer "F.Cu")
		(net "M_A_CPU0_SA_PAR")
	)
	(segment
		(start 333.365094 -253.649226)
		(end 332.476094 -253.649226)
		(width 0.088646)
		(layer "F.Cu")
		(net "M_A_CPU0_SA_PAR")
	)
	(segment
		(start 301.343314 -259.366766)
		(end 302.530002 -259.366766)
		(width 0.20066)
		(layer "F.Cu")
		(net "M_A_CPU0_SA_PAR")
	)
	(segment
		(start 333.644494 -253.776226)
		(end 333.365094 -253.649226)
		(width 0.088646)
		(layer "F.Cu")
		(net "M_A_CPU0_SA_PAR")
	)
	(segment
		(start 303.788318 -260.625082)
		(end 304.319178 -260.625082)
		(width 0.20066)
		(layer "F.Cu")
		(net "M_A_CPU0_SA_PAR")
	)
	(segment
		(start 304.35677 -260.625082)
		(end 304.37328 -260.641592)
		(width 0.101854)
		(layer "F.Cu")
		(net "M_A_CPU0_SA_PAR")
	)
	(segment
		(start 311.91708 -260.625082)
		(end 311.735216 -260.625082)
		(width 0.20066)
		(layer "F.Cu")
		(net "M_A_CPU0_SA_PAR")
	)
	(segment
		(start 304.319178 -260.625082)
		(end 304.35677 -260.625082)
		(width 0.101854)
		(layer "F.Cu")
		(net "M_A_CPU0_SA_PAR")
	)
	(segment
		(start 310.4769 -259.366766)
		(end 308.887114 -259.366766)
		(width 0.20066)
		(layer "F.Cu")
		(net "M_A_CPU0_SA_PAR")
	)
	(segment
		(start 322.518024 -256.237486)
		(end 322.139818 -256.237486)
		(width 0.1016)
		(layer "F.Cu")
		(net "M_A_CPU0_SA_PAR")
	)
	(segment
		(start 306.644294 -260.641592)
		(end 306.720748 -260.641592)
		(width 0.20066)
		(layer "F.Cu")
		(net "M_A_CPU0_SA_PAR")
	)
	(segment
		(start 311.969912 -260.641592)
		(end 311.953402 -260.625082)
		(width 0.101854)
		(layer "F.Cu")
		(net "M_A_CPU0_SA_PAR")
	)
	(segment
		(start 311.735216 -260.625082)
		(end 310.4769 -259.366766)
		(width 0.20066)
		(layer "F.Cu")
		(net "M_A_CPU0_SA_PAR")
	)
	(segment
		(start 313.874658 -260.641592)
		(end 311.969912 -260.641592)
		(width 0.1016)
		(layer "F.Cu")
		(net "M_A_CPU0_SA_PAR")
	)
	(segment
		(start 307.995574 -259.366766)
		(end 308.887114 -259.366766)
		(width 0.20066)
		(layer "F.Cu")
		(net "M_A_CPU0_SA_PAR")
	)
	(segment
		(start 321.883278 -256.237486)
		(end 316.772544 -258.354576)
		(width 0.20066)
		(layer "F.Cu")
		(net "M_A_CPU0_SA_PAR")
	)
	(segment
		(start 322.139818 -256.237486)
		(end 321.883278 -256.237486)
		(width 0.20066)
		(layer "F.Cu")
		(net "M_A_CPU0_SA_PAR")
	)
	(segment
		(start 306.720748 -260.641592)
		(end 307.995574 -259.366766)
		(width 0.20066)
		(layer "F.Cu")
		(net "M_A_CPU0_SA_PAR")
	)
	(segment
		(start 334.785716 -254.197612)
		(end 334.36433 -253.776226)
		(width 0.088646)
		(layer "F.Cu")
		(net "M_A_CPU0_SA_PAR")
	)
	(segment
		(start 322.596764 -256.316226)
		(end 322.518024 -256.237486)
		(width 0.1016)
		(layer "F.Cu")
		(net "M_A_CPU0_SA_PAR")
	)
	(segment
		(start 331.843634 -262.038084)
		(end 331.932534 -261.949184)
		(width 0.088646)
		(layer "F.Cu")
		(net "M_A_CPU0_SA_DQS_DP<9>")
	)
	(segment
		(start 331.05852 -262.038084)
		(end 331.265022 -262.038084)
		(width 0.088646)
		(layer "F.Cu")
		(net "M_A_CPU0_SA_DQS_DP<9>")
	)
	(segment
		(start 331.265022 -262.038084)
		(end 331.353922 -261.949184)
		(width 0.088646)
		(layer "F.Cu")
		(net "M_A_CPU0_SA_DQS_DP<9>")
	)
	(segment
		(start 310.400954 -273.39163)
		(end 310.66232 -273.652996)
		(width 0.20066)
		(layer "F.Cu")
		(net "M_A_CPU0_SA_DQS_DP<9>")
	)
	(segment
		(start 312.236104 -274.077938)
		(end 312.49747 -273.816572)
		(width 0.20066)
		(layer "F.Cu")
		(net "M_A_CPU0_SA_DQS_DP<9>")
	)
	(segment
		(start 322.699888 -268.057884)
		(end 322.751196 -268.057884)
		(width 0.1524)
		(layer "F.Cu")
		(net "M_A_CPU0_SA_DQS_DP<9>")
	)
	(segment
		(start 310.346598 -273.39163)
		(end 310.400954 -273.39163)
		(width 0.20066)
		(layer "F.Cu")
		(net "M_A_CPU0_SA_DQS_DP<9>")
	)
	(segment
		(start 318.563244 -272.194274)
		(end 318.563244 -272.018506)
		(width 0.20066)
		(layer "F.Cu")
		(net "M_A_CPU0_SA_DQS_DP<9>")
	)
	(segment
		(start 314.694062 -274.321016)
		(end 314.818522 -274.196556)
		(width 0.20066)
		(layer "F.Cu")
		(net "M_A_CPU0_SA_DQS_DP<9>")
	)
	(segment
		(start 315.420502 -274.196556)
		(end 315.544962 -274.321016)
		(width 0.20066)
		(layer "F.Cu")
		(net "M_A_CPU0_SA_DQS_DP<9>")
	)
	(segment
		(start 324.525132 -267.551154)
		(end 330.069952 -262.006334)
		(width 0.1524)
		(layer "F.Cu")
		(net "M_A_CPU0_SA_DQS_DP<9>")
	)
	(segment
		(start 306.17922 -274.077938)
		(end 306.40274 -274.077938)
		(width 0.20066)
		(layer "F.Cu")
		(net "M_A_CPU0_SA_DQS_DP<9>")
	)
	(segment
		(start 318.563244 -272.018506)
		(end 318.989202 -271.592548)
		(width 0.20066)
		(layer "F.Cu")
		(net "M_A_CPU0_SA_DQS_DP<9>")
	)
	(segment
		(start 321.645534 -268.936216)
		(end 322.071492 -268.510258)
		(width 0.20066)
		(layer "F.Cu")
		(net "M_A_CPU0_SA_DQS_DP<9>")
	)
	(segment
		(start 317.267336 -273.490436)
		(end 317.535814 -273.221958)
		(width 0.20066)
		(layer "F.Cu")
		(net "M_A_CPU0_SA_DQS_DP<9>")
	)
	(segment
		(start 312.987182 -273.816572)
		(end 313.267852 -273.816572)
		(width 0.20066)
		(layer "F.Cu")
		(net "M_A_CPU0_SA_DQS_DP<9>")
	)
	(segment
		(start 331.932534 -261.949184)
		(end 332.13294 -261.949184)
		(width 0.088646)
		(layer "F.Cu")
		(net "M_A_CPU0_SA_DQS_DP<9>")
	)
	(segment
		(start 334.116934 -261.840218)
		(end 334.117442 -261.840726)
		(width 0.088646)
		(layer "F.Cu")
		(net "M_A_CPU0_SA_DQS_DP<9>")
	)
	(segment
		(start 307.113178 -273.655536)
		(end 307.37683 -273.391884)
		(width 0.20066)
		(layer "F.Cu")
		(net "M_A_CPU0_SA_DQS_DP<9>")
	)
	(segment
		(start 320.192654 -270.565118)
		(end 320.618104 -270.139668)
		(width 0.20066)
		(layer "F.Cu")
		(net "M_A_CPU0_SA_DQS_DP<9>")
	)
	(segment
		(start 315.544962 -274.321016)
		(end 316.146942 -274.321016)
		(width 0.20066)
		(layer "F.Cu")
		(net "M_A_CPU0_SA_DQS_DP<9>")
	)
	(segment
		(start 322.751196 -268.057884)
		(end 323.049138 -267.760196)
		(width 0.1524)
		(layer "F.Cu")
		(net "M_A_CPU0_SA_DQS_DP<9>")
	)
	(segment
		(start 332.13294 -261.949184)
		(end 332.22184 -262.038084)
		(width 0.088646)
		(layer "F.Cu")
		(net "M_A_CPU0_SA_DQS_DP<9>")
	)
	(segment
		(start 310.66232 -273.652996)
		(end 311.24144 -273.652996)
		(width 0.20066)
		(layer "F.Cu")
		(net "M_A_CPU0_SA_DQS_DP<9>")
	)
	(segment
		(start 320.016632 -270.565118)
		(end 320.192654 -270.565118)
		(width 0.20066)
		(layer "F.Cu")
		(net "M_A_CPU0_SA_DQS_DP<9>")
	)
	(segment
		(start 317.535814 -273.045682)
		(end 317.961772 -272.619724)
		(width 0.20066)
		(layer "F.Cu")
		(net "M_A_CPU0_SA_DQS_DP<9>")
	)
	(segment
		(start 332.345538 -262.038084)
		(end 332.612238 -261.771384)
		(width 0.088646)
		(layer "F.Cu")
		(net "M_A_CPU0_SA_DQS_DP<9>")
	)
	(segment
		(start 332.612238 -261.771384)
		(end 332.906116 -261.771384)
		(width 0.088646)
		(layer "F.Cu")
		(net "M_A_CPU0_SA_DQS_DP<9>")
	)
	(segment
		(start 331.554328 -261.949184)
		(end 331.643228 -262.038084)
		(width 0.088646)
		(layer "F.Cu")
		(net "M_A_CPU0_SA_DQS_DP<9>")
	)
	(segment
		(start 313.267852 -273.816572)
		(end 313.268106 -273.816318)
		(width 0.20066)
		(layer "F.Cu")
		(net "M_A_CPU0_SA_DQS_DP<9>")
	)
	(segment
		(start 313.268106 -273.816318)
		(end 313.80176 -273.816318)
		(width 0.20066)
		(layer "F.Cu")
		(net "M_A_CPU0_SA_DQS_DP<9>")
	)
	(segment
		(start 322.071492 -268.510258)
		(end 322.247514 -268.510258)
		(width 0.20066)
		(layer "F.Cu")
		(net "M_A_CPU0_SA_DQS_DP<9>")
	)
	(segment
		(start 321.645534 -269.112238)
		(end 321.645534 -268.936216)
		(width 0.20066)
		(layer "F.Cu")
		(net "M_A_CPU0_SA_DQS_DP<9>")
	)
	(segment
		(start 318.989202 -271.592548)
		(end 319.165224 -271.592548)
		(width 0.20066)
		(layer "F.Cu")
		(net "M_A_CPU0_SA_DQS_DP<9>")
	)
	(segment
		(start 314.818522 -274.196556)
		(end 315.420502 -274.196556)
		(width 0.20066)
		(layer "F.Cu")
		(net "M_A_CPU0_SA_DQS_DP<9>")
	)
	(segment
		(start 334.478376 -262.021066)
		(end 334.596486 -262.252206)
		(width 0.088646)
		(layer "F.Cu")
		(net "M_A_CPU0_SA_DQS_DP<9>")
	)
	(segment
		(start 306.40274 -274.077938)
		(end 306.825142 -273.655536)
		(width 0.20066)
		(layer "F.Cu")
		(net "M_A_CPU0_SA_DQS_DP<9>")
	)
	(segment
		(start 323.25818 -267.551154)
		(end 324.525132 -267.551154)
		(width 0.1524)
		(layer "F.Cu")
		(net "M_A_CPU0_SA_DQS_DP<9>")
	)
	(segment
		(start 322.247514 -268.510258)
		(end 322.672964 -268.084808)
		(width 0.20066)
		(layer "F.Cu")
		(net "M_A_CPU0_SA_DQS_DP<9>")
	)
	(segment
		(start 314.064396 -274.321016)
		(end 314.694062 -274.321016)
		(width 0.20066)
		(layer "F.Cu")
		(net "M_A_CPU0_SA_DQS_DP<9>")
	)
	(segment
		(start 323.049138 -267.760196)
		(end 323.25818 -267.551154)
		(width 0.1524)
		(layer "F.Cu")
		(net "M_A_CPU0_SA_DQS_DP<9>")
	)
	(segment
		(start 332.22184 -262.038084)
		(end 332.345538 -262.038084)
		(width 0.088646)
		(layer "F.Cu")
		(net "M_A_CPU0_SA_DQS_DP<9>")
	)
	(segment
		(start 312.49747 -273.816572)
		(end 312.987182 -273.816572)
		(width 0.20066)
		(layer "F.Cu")
		(net "M_A_CPU0_SA_DQS_DP<9>")
	)
	(segment
		(start 322.672964 -268.084808)
		(end 322.699888 -268.057884)
		(width 0.1524)
		(layer "F.Cu")
		(net "M_A_CPU0_SA_DQS_DP<9>")
	)
	(segment
		(start 331.02677 -262.006334)
		(end 331.05852 -262.038084)
		(width 0.088646)
		(layer "F.Cu")
		(net "M_A_CPU0_SA_DQS_DP<9>")
	)
	(segment
		(start 331.353922 -261.949184)
		(end 331.554328 -261.949184)
		(width 0.088646)
		(layer "F.Cu")
		(net "M_A_CPU0_SA_DQS_DP<9>")
	)
	(segment
		(start 307.431186 -273.391884)
		(end 308.009544 -273.391884)
		(width 0.1016)
		(layer "F.Cu")
		(net "M_A_CPU0_SA_DQS_DP<9>")
	)
	(segment
		(start 317.535814 -273.221958)
		(end 317.535814 -273.045682)
		(width 0.20066)
		(layer "F.Cu")
		(net "M_A_CPU0_SA_DQS_DP<9>")
	)
	(segment
		(start 316.146942 -274.321016)
		(end 317.267336 -273.490436)
		(width 0.20066)
		(layer "F.Cu")
		(net "M_A_CPU0_SA_DQS_DP<9>")
	)
	(segment
		(start 331.004672 -262.006334)
		(end 331.02677 -262.006334)
		(width 0.088646)
		(layer "F.Cu")
		(net "M_A_CPU0_SA_DQS_DP<9>")
	)
	(segment
		(start 331.643228 -262.038084)
		(end 331.843634 -262.038084)
		(width 0.088646)
		(layer "F.Cu")
		(net "M_A_CPU0_SA_DQS_DP<9>")
	)
	(segment
		(start 321.044062 -269.537688)
		(end 321.220084 -269.537688)
		(width 0.20066)
		(layer "F.Cu")
		(net "M_A_CPU0_SA_DQS_DP<9>")
	)
	(segment
		(start 308.009798 -273.39163)
		(end 310.346598 -273.39163)
		(width 0.1016)
		(layer "F.Cu")
		(net "M_A_CPU0_SA_DQS_DP<9>")
	)
	(segment
		(start 307.37683 -273.391884)
		(end 307.431186 -273.391884)
		(width 0.20066)
		(layer "F.Cu")
		(net "M_A_CPU0_SA_DQS_DP<9>")
	)
	(segment
		(start 311.877456 -274.077938)
		(end 312.236104 -274.077938)
		(width 0.20066)
		(layer "F.Cu")
		(net "M_A_CPU0_SA_DQS_DP<9>")
	)
	(segment
		(start 334.596486 -262.252206)
		(end 334.680814 -262.336534)
		(width 0.088646)
		(layer "F.Cu")
		(net "M_A_CPU0_SA_DQS_DP<9>")
	)
	(segment
		(start 306.825142 -273.655536)
		(end 307.113178 -273.655536)
		(width 0.20066)
		(layer "F.Cu")
		(net "M_A_CPU0_SA_DQS_DP<9>")
	)
	(segment
		(start 305.917854 -273.816572)
		(end 306.17922 -274.077938)
		(width 0.20066)
		(layer "F.Cu")
		(net "M_A_CPU0_SA_DQS_DP<9>")
	)
	(segment
		(start 334.680814 -262.336534)
		(end 334.785716 -262.336534)
		(width 0.088646)
		(layer "F.Cu")
		(net "M_A_CPU0_SA_DQS_DP<9>")
	)
	(segment
		(start 321.220084 -269.537688)
		(end 321.645534 -269.112238)
		(width 0.20066)
		(layer "F.Cu")
		(net "M_A_CPU0_SA_DQS_DP<9>")
	)
	(segment
		(start 330.069952 -262.006334)
		(end 331.004672 -262.006334)
		(width 0.1524)
		(layer "F.Cu")
		(net "M_A_CPU0_SA_DQS_DP<9>")
	)
	(segment
		(start 320.618104 -270.139668)
		(end 320.618104 -269.963646)
		(width 0.20066)
		(layer "F.Cu")
		(net "M_A_CPU0_SA_DQS_DP<9>")
	)
	(segment
		(start 313.983878 -274.240498)
		(end 314.064396 -274.321016)
		(width 0.20066)
		(layer "F.Cu")
		(net "M_A_CPU0_SA_DQS_DP<9>")
	)
	(segment
		(start 311.24144 -273.652996)
		(end 311.877456 -274.077938)
		(width 0.20066)
		(layer "F.Cu")
		(net "M_A_CPU0_SA_DQS_DP<9>")
	)
	(segment
		(start 308.009544 -273.391884)
		(end 308.009798 -273.39163)
		(width 0.1016)
		(layer "F.Cu")
		(net "M_A_CPU0_SA_DQS_DP<9>")
	)
	(segment
		(start 305.443382 -273.816572)
		(end 305.917854 -273.816572)
		(width 0.20066)
		(layer "F.Cu")
		(net "M_A_CPU0_SA_DQS_DP<9>")
	)
	(segment
		(start 319.590674 -270.991076)
		(end 320.016632 -270.565118)
		(width 0.20066)
		(layer "F.Cu")
		(net "M_A_CPU0_SA_DQS_DP<9>")
	)
	(segment
		(start 334.117442 -261.840726)
		(end 334.478376 -262.021066)
		(width 0.088646)
		(layer "F.Cu")
		(net "M_A_CPU0_SA_DQS_DP<9>")
	)
	(segment
		(start 313.983878 -273.998436)
		(end 313.983878 -274.240498)
		(width 0.20066)
		(layer "F.Cu")
		(net "M_A_CPU0_SA_DQS_DP<9>")
	)
	(segment
		(start 317.961772 -272.619724)
		(end 318.137794 -272.619724)
		(width 0.20066)
		(layer "F.Cu")
		(net "M_A_CPU0_SA_DQS_DP<9>")
	)
	(segment
		(start 320.618104 -269.963646)
		(end 321.044062 -269.537688)
		(width 0.20066)
		(layer "F.Cu")
		(net "M_A_CPU0_SA_DQS_DP<9>")
	)
	(segment
		(start 319.590674 -271.167098)
		(end 319.590674 -270.991076)
		(width 0.20066)
		(layer "F.Cu")
		(net "M_A_CPU0_SA_DQS_DP<9>")
	)
	(segment
		(start 313.80176 -273.816318)
		(end 313.983878 -273.998436)
		(width 0.20066)
		(layer "F.Cu")
		(net "M_A_CPU0_SA_DQS_DP<9>")
	)
	(segment
		(start 318.137794 -272.619724)
		(end 318.563244 -272.194274)
		(width 0.20066)
		(layer "F.Cu")
		(net "M_A_CPU0_SA_DQS_DP<9>")
	)
	(segment
		(start 319.165224 -271.592548)
		(end 319.590674 -271.167098)
		(width 0.20066)
		(layer "F.Cu")
		(net "M_A_CPU0_SA_DQS_DP<9>")
	)
	(arc
		(start 333.188564 -261.847076)
		(mid 333.375762 -261.897219)
		(end 333.56296 -261.847076)
		(width 0.088646)
		(layer "F.Cu")
		(net "M_A_CPU0_SA_DQS_DP<9>")
	)
	(arc
		(start 333.56296 -261.847076)
		(mid 333.839064 -261.77109)
		(end 334.116934 -261.840218)
		(width 0.088646)
		(layer "F.Cu")
		(net "M_A_CPU0_SA_DQS_DP<9>")
	)
	(arc
		(start 332.906116 -261.771384)
		(mid 333.052324 -261.790633)
		(end 333.188564 -261.847076)
		(width 0.088646)
		(layer "F.Cu")
		(net "M_A_CPU0_SA_DQS_DP<9>")
	)
	(segment
		(start 321.77609 -281.297126)
		(end 321.600068 -281.297126)
		(width 0.20066)
		(layer "F.Cu")
		(net "M_A_CPU0_SA_DQS_DP<8>")
	)
	(segment
		(start 313.267852 -283.166566)
		(end 312.987182 -283.166566)
		(width 0.20066)
		(layer "F.Cu")
		(net "M_A_CPU0_SA_DQS_DP<8>")
	)
	(segment
		(start 331.383132 -267.684504)
		(end 331.383132 -267.831062)
		(width 0.088646)
		(layer "F.Cu")
		(net "M_A_CPU0_SA_DQS_DP<8>")
	)
	(segment
		(start 321.17411 -281.723084)
		(end 321.17411 -281.899106)
		(width 0.20066)
		(layer "F.Cu")
		(net "M_A_CPU0_SA_DQS_DP<8>")
	)
	(segment
		(start 306.153058 -283.40177)
		(end 306.415694 -283.40177)
		(width 0.20066)
		(layer "F.Cu")
		(net "M_A_CPU0_SA_DQS_DP<8>")
	)
	(segment
		(start 307.77942 -282.741878)
		(end 310.070754 -282.741878)
		(width 0.1016)
		(layer "F.Cu")
		(net "M_A_CPU0_SA_DQS_DP<8>")
	)
	(segment
		(start 305.917854 -283.166566)
		(end 306.153058 -283.40177)
		(width 0.20066)
		(layer "F.Cu")
		(net "M_A_CPU0_SA_DQS_DP<8>")
	)
	(segment
		(start 325.066914 -274.102576)
		(end 323.700902 -276.62505)
		(width 0.1524)
		(layer "F.Cu")
		(net "M_A_CPU0_SA_DQS_DP<8>")
	)
	(segment
		(start 334.249522 -266.79017)
		(end 334.117442 -266.72413)
		(width 0.088646)
		(layer "F.Cu")
		(net "M_A_CPU0_SA_DQS_DP<8>")
	)
	(segment
		(start 306.811934 -283.00553)
		(end 307.278786 -283.00553)
		(width 0.20066)
		(layer "F.Cu")
		(net "M_A_CPU0_SA_DQS_DP<8>")
	)
	(segment
		(start 316.765686 -283.689044)
		(end 316.641226 -283.564584)
		(width 0.20066)
		(layer "F.Cu")
		(net "M_A_CPU0_SA_DQS_DP<8>")
	)
	(segment
		(start 323.017134 -279.879806)
		(end 322.749418 -280.37536)
		(width 0.1524)
		(layer "F.Cu")
		(net "M_A_CPU0_SA_DQS_DP<8>")
	)
	(segment
		(start 333.655162 -266.687554)
		(end 333.655162 -266.688062)
		(width 0.088646)
		(layer "F.Cu")
		(net "M_A_CPU0_SA_DQS_DP<8>")
	)
	(segment
		(start 331.780896 -267.433298)
		(end 331.65542 -267.558774)
		(width 0.088646)
		(layer "F.Cu")
		(net "M_A_CPU0_SA_DQS_DP<8>")
	)
	(segment
		(start 310.070754 -282.741878)
		(end 310.081676 -282.730956)
		(width 0.1016)
		(layer "F.Cu")
		(net "M_A_CPU0_SA_DQS_DP<8>")
	)
	(segment
		(start 306.415694 -283.40177)
		(end 306.811934 -283.00553)
		(width 0.20066)
		(layer "F.Cu")
		(net "M_A_CPU0_SA_DQS_DP<8>")
	)
	(segment
		(start 305.443382 -283.166566)
		(end 305.917854 -283.166566)
		(width 0.20066)
		(layer "F.Cu")
		(net "M_A_CPU0_SA_DQS_DP<8>")
	)
	(segment
		(start 318.218566 -283.689044)
		(end 318.094106 -283.564584)
		(width 0.20066)
		(layer "F.Cu")
		(net "M_A_CPU0_SA_DQS_DP<8>")
	)
	(segment
		(start 311.877456 -283.427932)
		(end 312.236104 -283.427932)
		(width 0.20066)
		(layer "F.Cu")
		(net "M_A_CPU0_SA_DQS_DP<8>")
	)
	(segment
		(start 321.600068 -281.297126)
		(end 321.17411 -281.723084)
		(width 0.20066)
		(layer "F.Cu")
		(net "M_A_CPU0_SA_DQS_DP<8>")
	)
	(segment
		(start 320.14668 -282.750514)
		(end 320.14668 -282.926536)
		(width 0.20066)
		(layer "F.Cu")
		(net "M_A_CPU0_SA_DQS_DP<8>")
	)
	(segment
		(start 331.165454 -268.004036)
		(end 331.14996 -268.01953)
		(width 0.088646)
		(layer "F.Cu")
		(net "M_A_CPU0_SA_DQS_DP<8>")
	)
	(segment
		(start 315.312806 -283.689044)
		(end 315.188346 -283.564584)
		(width 0.20066)
		(layer "F.Cu")
		(net "M_A_CPU0_SA_DQS_DP<8>")
	)
	(segment
		(start 333.539592 -266.744704)
		(end 333.512922 -266.771628)
		(width 0.088646)
		(layer "F.Cu")
		(net "M_A_CPU0_SA_DQS_DP<8>")
	)
	(segment
		(start 313.97829 -283.573982)
		(end 313.97829 -283.342842)
		(width 0.20066)
		(layer "F.Cu")
		(net "M_A_CPU0_SA_DQS_DP<8>")
	)
	(segment
		(start 313.268106 -283.166312)
		(end 313.267852 -283.166566)
		(width 0.20066)
		(layer "F.Cu")
		(net "M_A_CPU0_SA_DQS_DP<8>")
	)
	(segment
		(start 319.922906 -283.15031)
		(end 318.728598 -283.644848)
		(width 0.20066)
		(layer "F.Cu")
		(net "M_A_CPU0_SA_DQS_DP<8>")
	)
	(segment
		(start 322.228464 -280.844752)
		(end 322.20154 -280.871676)
		(width 0.1524)
		(layer "F.Cu")
		(net "M_A_CPU0_SA_DQS_DP<8>")
	)
	(segment
		(start 318.506856 -283.689044)
		(end 318.218566 -283.689044)
		(width 0.20066)
		(layer "F.Cu")
		(net "M_A_CPU0_SA_DQS_DP<8>")
	)
	(segment
		(start 312.236104 -283.427932)
		(end 312.49747 -283.166566)
		(width 0.20066)
		(layer "F.Cu")
		(net "M_A_CPU0_SA_DQS_DP<8>")
	)
	(segment
		(start 334.117442 -266.72413)
		(end 334.116934 -266.723622)
		(width 0.088646)
		(layer "F.Cu")
		(net "M_A_CPU0_SA_DQS_DP<8>")
	)
	(segment
		(start 334.383888 -267.053822)
		(end 334.249522 -266.79017)
		(width 0.088646)
		(layer "F.Cu")
		(net "M_A_CPU0_SA_DQS_DP<8>")
	)
	(segment
		(start 314.586366 -283.564584)
		(end 314.461906 -283.689044)
		(width 0.20066)
		(layer "F.Cu")
		(net "M_A_CPU0_SA_DQS_DP<8>")
	)
	(segment
		(start 320.14668 -282.926536)
		(end 319.922906 -283.15031)
		(width 0.20066)
		(layer "F.Cu")
		(net "M_A_CPU0_SA_DQS_DP<8>")
	)
	(segment
		(start 332.525624 -266.68857)
		(end 332.450948 -266.763246)
		(width 0.088646)
		(layer "F.Cu")
		(net "M_A_CPU0_SA_DQS_DP<8>")
	)
	(segment
		(start 322.20154 -280.871676)
		(end 321.77609 -281.297126)
		(width 0.20066)
		(layer "F.Cu")
		(net "M_A_CPU0_SA_DQS_DP<8>")
	)
	(segment
		(start 307.768752 -282.73121)
		(end 307.77942 -282.741878)
		(width 0.1016)
		(layer "F.Cu")
		(net "M_A_CPU0_SA_DQS_DP<8>")
	)
	(segment
		(start 314.093352 -283.689044)
		(end 313.97829 -283.573982)
		(width 0.20066)
		(layer "F.Cu")
		(net "M_A_CPU0_SA_DQS_DP<8>")
	)
	(segment
		(start 333.232252 -266.771628)
		(end 333.149194 -266.68857)
		(width 0.088646)
		(layer "F.Cu")
		(net "M_A_CPU0_SA_DQS_DP<8>")
	)
	(segment
		(start 315.914786 -283.689044)
		(end 315.312806 -283.689044)
		(width 0.20066)
		(layer "F.Cu")
		(net "M_A_CPU0_SA_DQS_DP<8>")
	)
	(segment
		(start 307.278786 -283.00553)
		(end 307.553106 -282.73121)
		(width 0.20066)
		(layer "F.Cu")
		(net "M_A_CPU0_SA_DQS_DP<8>")
	)
	(segment
		(start 331.383132 -267.831062)
		(end 331.210158 -268.004036)
		(width 0.088646)
		(layer "F.Cu")
		(net "M_A_CPU0_SA_DQS_DP<8>")
	)
	(segment
		(start 318.728598 -283.644848)
		(end 318.506856 -283.689044)
		(width 0.20066)
		(layer "F.Cu")
		(net "M_A_CPU0_SA_DQS_DP<8>")
	)
	(segment
		(start 322.279772 -280.844752)
		(end 322.228464 -280.844752)
		(width 0.1524)
		(layer "F.Cu")
		(net "M_A_CPU0_SA_DQS_DP<8>")
	)
	(segment
		(start 317.492126 -283.564584)
		(end 317.367666 -283.689044)
		(width 0.20066)
		(layer "F.Cu")
		(net "M_A_CPU0_SA_DQS_DP<8>")
	)
	(segment
		(start 331.14996 -268.01953)
		(end 325.066914 -274.102576)
		(width 0.1524)
		(layer "F.Cu")
		(net "M_A_CPU0_SA_DQS_DP<8>")
	)
	(segment
		(start 307.553106 -282.73121)
		(end 307.76291 -282.73121)
		(width 0.20066)
		(layer "F.Cu")
		(net "M_A_CPU0_SA_DQS_DP<8>")
	)
	(segment
		(start 331.906626 -267.16101)
		(end 331.780896 -267.28674)
		(width 0.088646)
		(layer "F.Cu")
		(net "M_A_CPU0_SA_DQS_DP<8>")
	)
	(segment
		(start 310.088026 -282.730956)
		(end 310.395366 -282.730956)
		(width 0.20066)
		(layer "F.Cu")
		(net "M_A_CPU0_SA_DQS_DP<8>")
	)
	(segment
		(start 331.780896 -267.28674)
		(end 331.780896 -267.433298)
		(width 0.088646)
		(layer "F.Cu")
		(net "M_A_CPU0_SA_DQS_DP<8>")
	)
	(segment
		(start 311.24144 -283.00299)
		(end 311.877456 -283.427932)
		(width 0.20066)
		(layer "F.Cu")
		(net "M_A_CPU0_SA_DQS_DP<8>")
	)
	(segment
		(start 316.039246 -283.564584)
		(end 315.914786 -283.689044)
		(width 0.20066)
		(layer "F.Cu")
		(net "M_A_CPU0_SA_DQS_DP<8>")
	)
	(segment
		(start 315.188346 -283.564584)
		(end 314.586366 -283.564584)
		(width 0.20066)
		(layer "F.Cu")
		(net "M_A_CPU0_SA_DQS_DP<8>")
	)
	(segment
		(start 332.17866 -266.888976)
		(end 332.17866 -267.035534)
		(width 0.088646)
		(layer "F.Cu")
		(net "M_A_CPU0_SA_DQS_DP<8>")
	)
	(segment
		(start 312.49747 -283.166566)
		(end 312.987182 -283.166566)
		(width 0.20066)
		(layer "F.Cu")
		(net "M_A_CPU0_SA_DQS_DP<8>")
	)
	(segment
		(start 313.97829 -283.342842)
		(end 313.80176 -283.166312)
		(width 0.20066)
		(layer "F.Cu")
		(net "M_A_CPU0_SA_DQS_DP<8>")
	)
	(segment
		(start 321.17411 -281.899106)
		(end 320.74866 -282.324556)
		(width 0.20066)
		(layer "F.Cu")
		(net "M_A_CPU0_SA_DQS_DP<8>")
	)
	(segment
		(start 332.17866 -267.035534)
		(end 332.053184 -267.16101)
		(width 0.088646)
		(layer "F.Cu")
		(net "M_A_CPU0_SA_DQS_DP<8>")
	)
	(segment
		(start 314.461906 -283.689044)
		(end 314.093352 -283.689044)
		(width 0.20066)
		(layer "F.Cu")
		(net "M_A_CPU0_SA_DQS_DP<8>")
	)
	(segment
		(start 332.30439 -266.763246)
		(end 332.17866 -266.888976)
		(width 0.088646)
		(layer "F.Cu")
		(net "M_A_CPU0_SA_DQS_DP<8>")
	)
	(segment
		(start 331.65542 -267.558774)
		(end 331.508862 -267.558774)
		(width 0.088646)
		(layer "F.Cu")
		(net "M_A_CPU0_SA_DQS_DP<8>")
	)
	(segment
		(start 322.749418 -280.37536)
		(end 322.279772 -280.844752)
		(width 0.1524)
		(layer "F.Cu")
		(net "M_A_CPU0_SA_DQS_DP<8>")
	)
	(segment
		(start 332.450948 -266.763246)
		(end 332.30439 -266.763246)
		(width 0.088646)
		(layer "F.Cu")
		(net "M_A_CPU0_SA_DQS_DP<8>")
	)
	(segment
		(start 331.508862 -267.558774)
		(end 331.383132 -267.684504)
		(width 0.088646)
		(layer "F.Cu")
		(net "M_A_CPU0_SA_DQS_DP<8>")
	)
	(segment
		(start 331.210158 -268.004036)
		(end 331.165454 -268.004036)
		(width 0.088646)
		(layer "F.Cu")
		(net "M_A_CPU0_SA_DQS_DP<8>")
	)
	(segment
		(start 317.367666 -283.689044)
		(end 316.765686 -283.689044)
		(width 0.20066)
		(layer "F.Cu")
		(net "M_A_CPU0_SA_DQS_DP<8>")
	)
	(segment
		(start 333.512922 -266.771628)
		(end 333.232252 -266.771628)
		(width 0.088646)
		(layer "F.Cu")
		(net "M_A_CPU0_SA_DQS_DP<8>")
	)
	(segment
		(start 310.6674 -283.00299)
		(end 311.24144 -283.00299)
		(width 0.20066)
		(layer "F.Cu")
		(net "M_A_CPU0_SA_DQS_DP<8>")
	)
	(segment
		(start 332.053184 -267.16101)
		(end 331.906626 -267.16101)
		(width 0.088646)
		(layer "F.Cu")
		(net "M_A_CPU0_SA_DQS_DP<8>")
	)
	(segment
		(start 310.081676 -282.730956)
		(end 310.088026 -282.730956)
		(width 0.1016)
		(layer "F.Cu")
		(net "M_A_CPU0_SA_DQS_DP<8>")
	)
	(segment
		(start 323.700902 -276.62505)
		(end 323.017134 -279.879806)
		(width 0.1524)
		(layer "F.Cu")
		(net "M_A_CPU0_SA_DQS_DP<8>")
	)
	(segment
		(start 318.094106 -283.564584)
		(end 317.492126 -283.564584)
		(width 0.20066)
		(layer "F.Cu")
		(net "M_A_CPU0_SA_DQS_DP<8>")
	)
	(segment
		(start 307.76291 -282.73121)
		(end 307.768752 -282.73121)
		(width 0.101854)
		(layer "F.Cu")
		(net "M_A_CPU0_SA_DQS_DP<8>")
	)
	(segment
		(start 316.641226 -283.564584)
		(end 316.039246 -283.564584)
		(width 0.20066)
		(layer "F.Cu")
		(net "M_A_CPU0_SA_DQS_DP<8>")
	)
	(segment
		(start 320.74866 -282.324556)
		(end 320.572638 -282.324556)
		(width 0.20066)
		(layer "F.Cu")
		(net "M_A_CPU0_SA_DQS_DP<8>")
	)
	(segment
		(start 313.80176 -283.166312)
		(end 313.268106 -283.166312)
		(width 0.20066)
		(layer "F.Cu")
		(net "M_A_CPU0_SA_DQS_DP<8>")
	)
	(segment
		(start 310.395366 -282.730956)
		(end 310.6674 -283.00299)
		(width 0.20066)
		(layer "F.Cu")
		(net "M_A_CPU0_SA_DQS_DP<8>")
	)
	(segment
		(start 333.149194 -266.68857)
		(end 332.525624 -266.68857)
		(width 0.088646)
		(layer "F.Cu")
		(net "M_A_CPU0_SA_DQS_DP<8>")
	)
	(segment
		(start 320.572638 -282.324556)
		(end 320.14668 -282.750514)
		(width 0.20066)
		(layer "F.Cu")
		(net "M_A_CPU0_SA_DQS_DP<8>")
	)
	(arc
		(start 334.116934 -266.723622)
		(mid 333.889912 -266.656161)
		(end 333.655162 -266.687554)
		(width 0.088646)
		(layer "F.Cu")
		(net "M_A_CPU0_SA_DQS_DP<8>")
	)
	(arc
		(start 334.785716 -267.219938)
		(mid 334.554084 -267.211126)
		(end 334.383888 -267.053822)
		(width 0.088646)
		(layer "F.Cu")
		(net "M_A_CPU0_SA_DQS_DP<8>")
	)
	(arc
		(start 333.655162 -266.688062)
		(mid 333.595765 -266.713092)
		(end 333.539592 -266.744704)
		(width 0.088646)
		(layer "F.Cu")
		(net "M_A_CPU0_SA_DQS_DP<8>")
	)
	(segment
		(start 320.651378 -292.885368)
		(end 321.253358 -292.885368)
		(width 0.20066)
		(layer "F.Cu")
		(net "M_A_CPU0_SA_DQS_DP<7>")
	)
	(segment
		(start 317.019178 -293.009828)
		(end 317.621158 -293.009828)
		(width 0.20066)
		(layer "F.Cu")
		(net "M_A_CPU0_SA_DQS_DP<7>")
	)
	(segment
		(start 319.198498 -292.885368)
		(end 319.800478 -292.885368)
		(width 0.20066)
		(layer "F.Cu")
		(net "M_A_CPU0_SA_DQS_DP<7>")
	)
	(segment
		(start 334.116934 -271.607026)
		(end 334.117442 -271.607534)
		(width 0.088646)
		(layer "F.Cu")
		(net "M_A_CPU0_SA_DQS_DP<7>")
	)
	(segment
		(start 325.754238 -290.683696)
		(end 325.93026 -290.683696)
		(width 0.20066)
		(layer "F.Cu")
		(net "M_A_CPU0_SA_DQS_DP<7>")
	)
	(segment
		(start 326.76338 -289.749738)
		(end 326.76338 -281.567382)
		(width 0.1524)
		(layer "F.Cu")
		(net "M_A_CPU0_SA_DQS_DP<7>")
	)
	(segment
		(start 316.894718 -292.885368)
		(end 317.019178 -293.009828)
		(width 0.20066)
		(layer "F.Cu")
		(net "M_A_CPU0_SA_DQS_DP<7>")
	)
	(segment
		(start 313.892438 -292.51656)
		(end 314.001404 -292.625526)
		(width 0.20066)
		(layer "F.Cu")
		(net "M_A_CPU0_SA_DQS_DP<7>")
	)
	(segment
		(start 310.891682 -292.352984)
		(end 311.527698 -292.777926)
		(width 0.20066)
		(layer "F.Cu")
		(net "M_A_CPU0_SA_DQS_DP<7>")
	)
	(segment
		(start 332.581504 -272.127472)
		(end 332.725268 -271.983454)
		(width 0.088646)
		(layer "F.Cu")
		(net "M_A_CPU0_SA_DQS_DP<7>")
	)
	(segment
		(start 314.839858 -292.885368)
		(end 315.441838 -292.885368)
		(width 0.20066)
		(layer "F.Cu")
		(net "M_A_CPU0_SA_DQS_DP<7>")
	)
	(segment
		(start 334.117442 -271.607534)
		(end 334.478376 -271.787874)
		(width 0.088646)
		(layer "F.Cu")
		(net "M_A_CPU0_SA_DQS_DP<7>")
	)
	(segment
		(start 324.30085 -292.137084)
		(end 324.726808 -291.711126)
		(width 0.20066)
		(layer "F.Cu")
		(net "M_A_CPU0_SA_DQS_DP<7>")
	)
	(segment
		(start 331.59192 -273.257264)
		(end 331.72654 -273.122644)
		(width 0.088646)
		(layer "F.Cu")
		(net "M_A_CPU0_SA_DQS_DP<7>")
	)
	(segment
		(start 324.726808 -291.711126)
		(end 324.90283 -291.711126)
		(width 0.20066)
		(layer "F.Cu")
		(net "M_A_CPU0_SA_DQS_DP<7>")
	)
	(segment
		(start 319.800478 -292.885368)
		(end 319.924938 -293.009828)
		(width 0.20066)
		(layer "F.Cu")
		(net "M_A_CPU0_SA_DQS_DP<7>")
	)
	(segment
		(start 331.72654 -273.122644)
		(end 331.72654 -272.982436)
		(width 0.088646)
		(layer "F.Cu")
		(net "M_A_CPU0_SA_DQS_DP<7>")
	)
	(segment
		(start 318.472058 -293.009828)
		(end 319.074038 -293.009828)
		(width 0.20066)
		(layer "F.Cu")
		(net "M_A_CPU0_SA_DQS_DP<7>")
	)
	(segment
		(start 334.478376 -271.787874)
		(end 334.621886 -272.068798)
		(width 0.088646)
		(layer "F.Cu")
		(net "M_A_CPU0_SA_DQS_DP<7>")
	)
	(segment
		(start 312.497216 -292.516814)
		(end 312.987182 -292.516814)
		(width 0.20066)
		(layer "F.Cu")
		(net "M_A_CPU0_SA_DQS_DP<7>")
	)
	(segment
		(start 331.72654 -272.982436)
		(end 331.870304 -272.838418)
		(width 0.088646)
		(layer "F.Cu")
		(net "M_A_CPU0_SA_DQS_DP<7>")
	)
	(segment
		(start 331.320394 -273.483324)
		(end 331.365098 -273.483324)
		(width 0.088646)
		(layer "F.Cu")
		(net "M_A_CPU0_SA_DQS_DP<7>")
	)
	(segment
		(start 331.870304 -272.838418)
		(end 332.010512 -272.838418)
		(width 0.088646)
		(layer "F.Cu")
		(net "M_A_CPU0_SA_DQS_DP<7>")
	)
	(segment
		(start 326.433942 -290.231322)
		(end 326.65543 -290.009834)
		(width 0.1524)
		(layer "F.Cu")
		(net "M_A_CPU0_SA_DQS_DP<7>")
	)
	(segment
		(start 317.745618 -292.885368)
		(end 318.347598 -292.885368)
		(width 0.20066)
		(layer "F.Cu")
		(net "M_A_CPU0_SA_DQS_DP<7>")
	)
	(segment
		(start 310.070754 -292.091872)
		(end 310.081676 -292.08095)
		(width 0.1016)
		(layer "F.Cu")
		(net "M_A_CPU0_SA_DQS_DP<7>")
	)
	(segment
		(start 310.081676 -292.08095)
		(end 310.088026 -292.08095)
		(width 0.1016)
		(layer "F.Cu")
		(net "M_A_CPU0_SA_DQS_DP<7>")
	)
	(segment
		(start 310.176418 -292.08095)
		(end 310.448452 -292.352984)
		(width 0.20066)
		(layer "F.Cu")
		(net "M_A_CPU0_SA_DQS_DP<7>")
	)
	(segment
		(start 332.010512 -272.838418)
		(end 332.154022 -272.694908)
		(width 0.088646)
		(layer "F.Cu")
		(net "M_A_CPU0_SA_DQS_DP<7>")
	)
	(segment
		(start 312.236104 -292.777926)
		(end 312.497216 -292.516814)
		(width 0.20066)
		(layer "F.Cu")
		(net "M_A_CPU0_SA_DQS_DP<7>")
	)
	(segment
		(start 306.40274 -292.777926)
		(end 306.825142 -292.355524)
		(width 0.20066)
		(layer "F.Cu")
		(net "M_A_CPU0_SA_DQS_DP<7>")
	)
	(segment
		(start 313.892184 -292.516814)
		(end 313.892438 -292.51656)
		(width 0.20066)
		(layer "F.Cu")
		(net "M_A_CPU0_SA_DQS_DP<7>")
	)
	(segment
		(start 316.292738 -292.885368)
		(end 316.894718 -292.885368)
		(width 0.20066)
		(layer "F.Cu")
		(net "M_A_CPU0_SA_DQS_DP<7>")
	)
	(segment
		(start 319.924938 -293.009828)
		(end 320.526918 -293.009828)
		(width 0.20066)
		(layer "F.Cu")
		(net "M_A_CPU0_SA_DQS_DP<7>")
	)
	(segment
		(start 332.725268 -271.983454)
		(end 332.865476 -271.983454)
		(width 0.088646)
		(layer "F.Cu")
		(net "M_A_CPU0_SA_DQS_DP<7>")
	)
	(segment
		(start 319.074038 -293.009828)
		(end 319.198498 -292.885368)
		(width 0.20066)
		(layer "F.Cu")
		(net "M_A_CPU0_SA_DQS_DP<7>")
	)
	(segment
		(start 325.93026 -290.683696)
		(end 326.35571 -290.258246)
		(width 0.20066)
		(layer "F.Cu")
		(net "M_A_CPU0_SA_DQS_DP<7>")
	)
	(segment
		(start 317.621158 -293.009828)
		(end 317.745618 -292.885368)
		(width 0.20066)
		(layer "F.Cu")
		(net "M_A_CPU0_SA_DQS_DP<7>")
	)
	(segment
		(start 307.76291 -292.08603)
		(end 307.768752 -292.091872)
		(width 0.1016)
		(layer "F.Cu")
		(net "M_A_CPU0_SA_DQS_DP<7>")
	)
	(segment
		(start 334.621886 -272.068798)
		(end 334.65643 -272.103342)
		(width 0.088646)
		(layer "F.Cu")
		(net "M_A_CPU0_SA_DQS_DP<7>")
	)
	(segment
		(start 314.715398 -293.009828)
		(end 314.839858 -292.885368)
		(width 0.20066)
		(layer "F.Cu")
		(net "M_A_CPU0_SA_DQS_DP<7>")
	)
	(segment
		(start 315.441838 -292.885368)
		(end 315.566298 -293.009828)
		(width 0.20066)
		(layer "F.Cu")
		(net "M_A_CPU0_SA_DQS_DP<7>")
	)
	(segment
		(start 310.088026 -292.08095)
		(end 310.176418 -292.08095)
		(width 0.20066)
		(layer "F.Cu")
		(net "M_A_CPU0_SA_DQS_DP<7>")
	)
	(segment
		(start 307.768752 -292.091872)
		(end 310.070754 -292.091872)
		(width 0.1016)
		(layer "F.Cu")
		(net "M_A_CPU0_SA_DQS_DP<7>")
	)
	(segment
		(start 333.222346 -271.787112)
		(end 333.3623 -271.787112)
		(width 0.088646)
		(layer "F.Cu")
		(net "M_A_CPU0_SA_DQS_DP<7>")
	)
	(segment
		(start 312.987182 -292.516814)
		(end 313.892184 -292.516814)
		(width 0.20066)
		(layer "F.Cu")
		(net "M_A_CPU0_SA_DQS_DP<7>")
	)
	(segment
		(start 311.527698 -292.777926)
		(end 312.236104 -292.777926)
		(width 0.20066)
		(layer "F.Cu")
		(net "M_A_CPU0_SA_DQS_DP<7>")
	)
	(segment
		(start 332.865476 -271.983454)
		(end 332.94828 -271.90065)
		(width 0.088646)
		(layer "F.Cu")
		(net "M_A_CPU0_SA_DQS_DP<7>")
	)
	(segment
		(start 325.32828 -291.109654)
		(end 325.754238 -290.683696)
		(width 0.20066)
		(layer "F.Cu")
		(net "M_A_CPU0_SA_DQS_DP<7>")
	)
	(segment
		(start 316.168278 -293.009828)
		(end 316.292738 -292.885368)
		(width 0.20066)
		(layer "F.Cu")
		(net "M_A_CPU0_SA_DQS_DP<7>")
	)
	(segment
		(start 307.113178 -292.355524)
		(end 307.382672 -292.08603)
		(width 0.20066)
		(layer "F.Cu")
		(net "M_A_CPU0_SA_DQS_DP<7>")
	)
	(segment
		(start 326.65543 -290.009834)
		(end 326.76338 -289.749738)
		(width 0.1524)
		(layer "F.Cu")
		(net "M_A_CPU0_SA_DQS_DP<7>")
	)
	(segment
		(start 332.437994 -272.410936)
		(end 332.581504 -272.267426)
		(width 0.088646)
		(layer "F.Cu")
		(net "M_A_CPU0_SA_DQS_DP<7>")
	)
	(segment
		(start 318.347598 -292.885368)
		(end 318.472058 -293.009828)
		(width 0.20066)
		(layer "F.Cu")
		(net "M_A_CPU0_SA_DQS_DP<7>")
	)
	(segment
		(start 320.526918 -293.009828)
		(end 320.651378 -292.885368)
		(width 0.20066)
		(layer "F.Cu")
		(net "M_A_CPU0_SA_DQS_DP<7>")
	)
	(segment
		(start 306.17922 -292.777926)
		(end 306.40274 -292.777926)
		(width 0.20066)
		(layer "F.Cu")
		(net "M_A_CPU0_SA_DQS_DP<7>")
	)
	(segment
		(start 314.001404 -292.833806)
		(end 314.177426 -293.009828)
		(width 0.20066)
		(layer "F.Cu")
		(net "M_A_CPU0_SA_DQS_DP<7>")
	)
	(segment
		(start 325.32828 -291.285676)
		(end 325.32828 -291.109654)
		(width 0.20066)
		(layer "F.Cu")
		(net "M_A_CPU0_SA_DQS_DP<7>")
	)
	(segment
		(start 322.766436 -293.009828)
		(end 324.196456 -292.4175)
		(width 0.20066)
		(layer "F.Cu")
		(net "M_A_CPU0_SA_DQS_DP<7>")
	)
	(segment
		(start 314.001404 -292.625526)
		(end 314.001404 -292.833806)
		(width 0.20066)
		(layer "F.Cu")
		(net "M_A_CPU0_SA_DQS_DP<7>")
	)
	(segment
		(start 306.825142 -292.355524)
		(end 307.113178 -292.355524)
		(width 0.20066)
		(layer "F.Cu")
		(net "M_A_CPU0_SA_DQS_DP<7>")
	)
	(segment
		(start 331.3049 -273.498818)
		(end 331.320394 -273.483324)
		(width 0.088646)
		(layer "F.Cu")
		(net "M_A_CPU0_SA_DQS_DP<7>")
	)
	(segment
		(start 305.918108 -292.516814)
		(end 306.17922 -292.777926)
		(width 0.20066)
		(layer "F.Cu")
		(net "M_A_CPU0_SA_DQS_DP<7>")
	)
	(segment
		(start 332.581504 -272.267426)
		(end 332.581504 -272.127472)
		(width 0.088646)
		(layer "F.Cu")
		(net "M_A_CPU0_SA_DQS_DP<7>")
	)
	(segment
		(start 331.365098 -273.483324)
		(end 331.591158 -273.257264)
		(width 0.088646)
		(layer "F.Cu")
		(net "M_A_CPU0_SA_DQS_DP<7>")
	)
	(segment
		(start 333.3623 -271.787112)
		(end 333.445866 -271.703546)
		(width 0.088646)
		(layer "F.Cu")
		(net "M_A_CPU0_SA_DQS_DP<7>")
	)
	(segment
		(start 326.35571 -290.258246)
		(end 326.382634 -290.231322)
		(width 0.1524)
		(layer "F.Cu")
		(net "M_A_CPU0_SA_DQS_DP<7>")
	)
	(segment
		(start 332.297786 -272.410936)
		(end 332.437994 -272.410936)
		(width 0.088646)
		(layer "F.Cu")
		(net "M_A_CPU0_SA_DQS_DP<7>")
	)
	(segment
		(start 314.177426 -293.009828)
		(end 314.715398 -293.009828)
		(width 0.20066)
		(layer "F.Cu")
		(net "M_A_CPU0_SA_DQS_DP<7>")
	)
	(segment
		(start 321.377818 -293.009828)
		(end 322.766436 -293.009828)
		(width 0.20066)
		(layer "F.Cu")
		(net "M_A_CPU0_SA_DQS_DP<7>")
	)
	(segment
		(start 334.65643 -272.103342)
		(end 334.785716 -272.103342)
		(width 0.088646)
		(layer "F.Cu")
		(net "M_A_CPU0_SA_DQS_DP<7>")
	)
	(segment
		(start 331.591158 -273.257264)
		(end 331.59192 -273.257264)
		(width 0.088646)
		(layer "F.Cu")
		(net "M_A_CPU0_SA_DQS_DP<7>")
	)
	(segment
		(start 327.483724 -277.965154)
		(end 328.22642 -276.577298)
		(width 0.1524)
		(layer "F.Cu")
		(net "M_A_CPU0_SA_DQS_DP<7>")
	)
	(segment
		(start 332.154022 -272.554954)
		(end 332.297786 -272.410936)
		(width 0.088646)
		(layer "F.Cu")
		(net "M_A_CPU0_SA_DQS_DP<7>")
	)
	(segment
		(start 321.253358 -292.885368)
		(end 321.377818 -293.009828)
		(width 0.20066)
		(layer "F.Cu")
		(net "M_A_CPU0_SA_DQS_DP<7>")
	)
	(segment
		(start 324.196456 -292.4175)
		(end 324.30085 -292.313106)
		(width 0.20066)
		(layer "F.Cu")
		(net "M_A_CPU0_SA_DQS_DP<7>")
	)
	(segment
		(start 328.22642 -276.577298)
		(end 331.3049 -273.498818)
		(width 0.1524)
		(layer "F.Cu")
		(net "M_A_CPU0_SA_DQS_DP<7>")
	)
	(segment
		(start 324.90283 -291.711126)
		(end 325.32828 -291.285676)
		(width 0.20066)
		(layer "F.Cu")
		(net "M_A_CPU0_SA_DQS_DP<7>")
	)
	(segment
		(start 305.443382 -292.516814)
		(end 305.918108 -292.516814)
		(width 0.20066)
		(layer "F.Cu")
		(net "M_A_CPU0_SA_DQS_DP<7>")
	)
	(segment
		(start 332.94828 -271.90065)
		(end 333.222346 -271.787112)
		(width 0.088646)
		(layer "F.Cu")
		(net "M_A_CPU0_SA_DQS_DP<7>")
	)
	(segment
		(start 310.448452 -292.352984)
		(end 310.891682 -292.352984)
		(width 0.20066)
		(layer "F.Cu")
		(net "M_A_CPU0_SA_DQS_DP<7>")
	)
	(segment
		(start 307.382672 -292.08603)
		(end 307.76291 -292.08603)
		(width 0.20066)
		(layer "F.Cu")
		(net "M_A_CPU0_SA_DQS_DP<7>")
	)
	(segment
		(start 326.76338 -281.567382)
		(end 327.483724 -277.965154)
		(width 0.1524)
		(layer "F.Cu")
		(net "M_A_CPU0_SA_DQS_DP<7>")
	)
	(segment
		(start 326.382634 -290.231322)
		(end 326.433942 -290.231322)
		(width 0.1524)
		(layer "F.Cu")
		(net "M_A_CPU0_SA_DQS_DP<7>")
	)
	(segment
		(start 332.154022 -272.694908)
		(end 332.154022 -272.554954)
		(width 0.088646)
		(layer "F.Cu")
		(net "M_A_CPU0_SA_DQS_DP<7>")
	)
	(segment
		(start 315.566298 -293.009828)
		(end 316.168278 -293.009828)
		(width 0.20066)
		(layer "F.Cu")
		(net "M_A_CPU0_SA_DQS_DP<7>")
	)
	(segment
		(start 324.30085 -292.313106)
		(end 324.30085 -292.137084)
		(width 0.20066)
		(layer "F.Cu")
		(net "M_A_CPU0_SA_DQS_DP<7>")
	)
	(arc
		(start 333.445866 -271.703546)
		(mid 333.501471 -271.654872)
		(end 333.56296 -271.613884)
		(width 0.088646)
		(layer "F.Cu")
		(net "M_A_CPU0_SA_DQS_DP<7>")
	)
	(arc
		(start 333.56296 -271.613884)
		(mid 333.839064 -271.537898)
		(end 334.116934 -271.607026)
		(width 0.088646)
		(layer "F.Cu")
		(net "M_A_CPU0_SA_DQS_DP<7>")
	)
	(segment
		(start 310.995568 -301.702978)
		(end 310.490616 -301.702978)
		(width 0.20066)
		(layer "F.Cu")
		(net "M_A_CPU0_SA_DQS_DP<6>")
	)
	(segment
		(start 314.092082 -301.866808)
		(end 312.987182 -301.866808)
		(width 0.20066)
		(layer "F.Cu")
		(net "M_A_CPU0_SA_DQS_DP<6>")
	)
	(segment
		(start 310.229504 -301.441866)
		(end 310.088026 -301.441866)
		(width 0.20066)
		(layer "F.Cu")
		(net "M_A_CPU0_SA_DQS_DP<6>")
	)
	(segment
		(start 307.76291 -301.436024)
		(end 307.565552 -301.436024)
		(width 0.20066)
		(layer "F.Cu")
		(net "M_A_CPU0_SA_DQS_DP<6>")
	)
	(segment
		(start 307.565552 -301.436024)
		(end 307.296058 -301.705518)
		(width 0.20066)
		(layer "F.Cu")
		(net "M_A_CPU0_SA_DQS_DP<6>")
	)
	(segment
		(start 312.497216 -301.866808)
		(end 312.236104 -302.12792)
		(width 0.20066)
		(layer "F.Cu")
		(net "M_A_CPU0_SA_DQS_DP<6>")
	)
	(segment
		(start 306.17922 -302.12792)
		(end 305.918108 -301.866808)
		(width 0.20066)
		(layer "F.Cu")
		(net "M_A_CPU0_SA_DQS_DP<6>")
	)
	(segment
		(start 312.987182 -301.866808)
		(end 312.497216 -301.866808)
		(width 0.20066)
		(layer "F.Cu")
		(net "M_A_CPU0_SA_DQS_DP<6>")
	)
	(segment
		(start 338.074762 -269.66164)
		(end 338.074762 -270.19758)
		(width 0.20066)
		(layer "F.Cu")
		(net "M_A_CPU0_SA_DQS_DP<6>")
	)
	(segment
		(start 307.296058 -301.705518)
		(end 306.935886 -301.705518)
		(width 0.20066)
		(layer "F.Cu")
		(net "M_A_CPU0_SA_DQS_DP<6>")
	)
	(segment
		(start 310.490616 -301.702978)
		(end 310.229504 -301.441866)
		(width 0.20066)
		(layer "F.Cu")
		(net "M_A_CPU0_SA_DQS_DP<6>")
	)
	(segment
		(start 305.918108 -301.866808)
		(end 305.443382 -301.866808)
		(width 0.20066)
		(layer "F.Cu")
		(net "M_A_CPU0_SA_DQS_DP<6>")
	)
	(segment
		(start 308.009544 -301.441866)
		(end 307.768752 -301.441866)
		(width 0.101854)
		(layer "F.Cu")
		(net "M_A_CPU0_SA_DQS_DP<6>")
	)
	(segment
		(start 306.935886 -301.705518)
		(end 306.513484 -302.12792)
		(width 0.20066)
		(layer "F.Cu")
		(net "M_A_CPU0_SA_DQS_DP<6>")
	)
	(segment
		(start 307.768752 -301.441866)
		(end 307.76291 -301.436024)
		(width 0.101854)
		(layer "F.Cu")
		(net "M_A_CPU0_SA_DQS_DP<6>")
	)
	(segment
		(start 311.631584 -302.12792)
		(end 310.995568 -301.702978)
		(width 0.20066)
		(layer "F.Cu")
		(net "M_A_CPU0_SA_DQS_DP<6>")
	)
	(segment
		(start 310.088026 -301.441866)
		(end 308.009544 -301.441866)
		(width 0.1016)
		(layer "F.Cu")
		(net "M_A_CPU0_SA_DQS_DP<6>")
	)
	(segment
		(start 312.236104 -302.12792)
		(end 311.631584 -302.12792)
		(width 0.20066)
		(layer "F.Cu")
		(net "M_A_CPU0_SA_DQS_DP<6>")
	)
	(segment
		(start 306.513484 -302.12792)
		(end 306.17922 -302.12792)
		(width 0.20066)
		(layer "F.Cu")
		(net "M_A_CPU0_SA_DQS_DP<6>")
	)
	(segment
		(start 315.621416 -297.332908)
		(end 315.621416 -300.189392)
		(width 0.18288)
		(layer "In2.Cu")
		(net "M_A_CPU0_SA_DQS_DP<6>")
	)
	(segment
		(start 318.038734 -291.496496)
		(end 317.87592 -291.563806)
		(width 0.18288)
		(layer "In2.Cu")
		(net "M_A_CPU0_SA_DQS_DP<6>")
	)
	(segment
		(start 328.60615 -276.152864)
		(end 324.312026 -280.446988)
		(width 0.18288)
		(layer "In2.Cu")
		(net "M_A_CPU0_SA_DQS_DP<6>")
	)
	(segment
		(start 338.074762 -270.19758)
		(end 338.38769 -270.19758)
		(width 0.088646)
		(layer "In2.Cu")
		(net "M_A_CPU0_SA_DQS_DP<6>")
	)
	(segment
		(start 332.354174 -270.675862)
		(end 329.82916 -273.200622)
		(width 0.18288)
		(layer "In2.Cu")
		(net "M_A_CPU0_SA_DQS_DP<6>")
	)
	(segment
		(start 323.296534 -282.89885)
		(end 320.397886 -285.797752)
		(width 0.18288)
		(layer "In2.Cu")
		(net "M_A_CPU0_SA_DQS_DP<6>")
	)
	(segment
		(start 316.884558 -294.283638)
		(end 316.721744 -294.351202)
		(width 0.18288)
		(layer "In2.Cu")
		(net "M_A_CPU0_SA_DQS_DP<6>")
	)
	(segment
		(start 316.511686 -294.858186)
		(end 316.57925 -295.020746)
		(width 0.18288)
		(layer "In2.Cu")
		(net "M_A_CPU0_SA_DQS_DP<6>")
	)
	(segment
		(start 317.87592 -291.563806)
		(end 317.666116 -292.071044)
		(width 0.18288)
		(layer "In2.Cu")
		(net "M_A_CPU0_SA_DQS_DP<6>")
	)
	(segment
		(start 337.700112 -270.19758)
		(end 337.700112 -270.179038)
		(width 0.088646)
		(layer "In2.Cu")
		(net "M_A_CPU0_SA_DQS_DP<6>")
	)
	(segment
		(start 334.97266 -269.707868)
		(end 334.973168 -269.708376)
		(width 0.088646)
		(layer "In2.Cu")
		(net "M_A_CPU0_SA_DQS_DP<6>")
	)
	(segment
		(start 332.55458 -270.55953)
		(end 332.438248 -270.675862)
		(width 0.088646)
		(layer "In2.Cu")
		(net "M_A_CPU0_SA_DQS_DP<6>")
	)
	(segment
		(start 316.364366 -295.539922)
		(end 316.021974 -295.681908)
		(width 0.18288)
		(layer "In2.Cu")
		(net "M_A_CPU0_SA_DQS_DP<6>")
	)
	(segment
		(start 317.39967 -293.0398)
		(end 317.236856 -293.10711)
		(width 0.18288)
		(layer "In2.Cu")
		(net "M_A_CPU0_SA_DQS_DP<6>")
	)
	(segment
		(start 333.833724 -270.522446)
		(end 332.644496 -270.522446)
		(width 0.088646)
		(layer "In2.Cu")
		(net "M_A_CPU0_SA_DQS_DP<6>")
	)
	(segment
		(start 318.198246 -290.78555)
		(end 318.265556 -290.94811)
		(width 0.18288)
		(layer "In2.Cu")
		(net "M_A_CPU0_SA_DQS_DP<6>")
	)
	(segment
		(start 320.397886 -285.797752)
		(end 318.570864 -290.211002)
		(width 0.18288)
		(layer "In2.Cu")
		(net "M_A_CPU0_SA_DQS_DP<6>")
	)
	(segment
		(start 317.026798 -293.614348)
		(end 317.094362 -293.776908)
		(width 0.18288)
		(layer "In2.Cu")
		(net "M_A_CPU0_SA_DQS_DP<6>")
	)
	(segment
		(start 338.27085 -270.516858)
		(end 338.26196 -270.521938)
		(width 0.088646)
		(layer "In2.Cu")
		(net "M_A_CPU0_SA_DQS_DP<6>")
	)
	(segment
		(start 315.621416 -300.189392)
		(end 314.93587 -301.84471)
		(width 0.18288)
		(layer "In2.Cu")
		(net "M_A_CPU0_SA_DQS_DP<6>")
	)
	(segment
		(start 334.785462 -269.758668)
		(end 334.597502 -269.758668)
		(width 0.088646)
		(layer "In2.Cu")
		(net "M_A_CPU0_SA_DQS_DP<6>")
	)
	(segment
		(start 338.38769 -270.19758)
		(end 338.44484 -270.25473)
		(width 0.088646)
		(layer "In2.Cu")
		(net "M_A_CPU0_SA_DQS_DP<6>")
	)
	(segment
		(start 315.634878 -296.61485)
		(end 315.777118 -296.956988)
		(width 0.18288)
		(layer "In2.Cu")
		(net "M_A_CPU0_SA_DQS_DP<6>")
	)
	(segment
		(start 314.349892 -302.124618)
		(end 314.092082 -301.866808)
		(width 0.18288)
		(layer "In2.Cu")
		(net "M_A_CPU0_SA_DQS_DP<6>")
	)
	(segment
		(start 329.82916 -273.200622)
		(end 328.60615 -276.152864)
		(width 0.18288)
		(layer "In2.Cu")
		(net "M_A_CPU0_SA_DQS_DP<6>")
	)
	(segment
		(start 315.777118 -296.956988)
		(end 315.621416 -297.332908)
		(width 0.18288)
		(layer "In2.Cu")
		(net "M_A_CPU0_SA_DQS_DP<6>")
	)
	(segment
		(start 317.666116 -292.071044)
		(end 317.733426 -292.233604)
		(width 0.18288)
		(layer "In2.Cu")
		(net "M_A_CPU0_SA_DQS_DP<6>")
	)
	(segment
		(start 316.721744 -294.351202)
		(end 316.511686 -294.858186)
		(width 0.18288)
		(layer "In2.Cu")
		(net "M_A_CPU0_SA_DQS_DP<6>")
	)
	(segment
		(start 317.733426 -292.233604)
		(end 317.39967 -293.0398)
		(width 0.18288)
		(layer "In2.Cu")
		(net "M_A_CPU0_SA_DQS_DP<6>")
	)
	(segment
		(start 316.021974 -295.681908)
		(end 315.634878 -296.61485)
		(width 0.18288)
		(layer "In2.Cu")
		(net "M_A_CPU0_SA_DQS_DP<6>")
	)
	(segment
		(start 334.597502 -269.758668)
		(end 333.833724 -270.522446)
		(width 0.088646)
		(layer "In2.Cu")
		(net "M_A_CPU0_SA_DQS_DP<6>")
	)
	(segment
		(start 332.438248 -270.675862)
		(end 332.354174 -270.675862)
		(width 0.088646)
		(layer "In2.Cu")
		(net "M_A_CPU0_SA_DQS_DP<6>")
	)
	(segment
		(start 317.236856 -293.10711)
		(end 317.026798 -293.614348)
		(width 0.18288)
		(layer "In2.Cu")
		(net "M_A_CPU0_SA_DQS_DP<6>")
	)
	(segment
		(start 332.644496 -270.522446)
		(end 332.55458 -270.55953)
		(width 0.088646)
		(layer "In2.Cu")
		(net "M_A_CPU0_SA_DQS_DP<6>")
	)
	(segment
		(start 317.094362 -293.776908)
		(end 316.884558 -294.283638)
		(width 0.18288)
		(layer "In2.Cu")
		(net "M_A_CPU0_SA_DQS_DP<6>")
	)
	(segment
		(start 318.40805 -290.278566)
		(end 318.198246 -290.78555)
		(width 0.18288)
		(layer "In2.Cu")
		(net "M_A_CPU0_SA_DQS_DP<6>")
	)
	(segment
		(start 314.656216 -302.124618)
		(end 314.349892 -302.124618)
		(width 0.18288)
		(layer "In2.Cu")
		(net "M_A_CPU0_SA_DQS_DP<6>")
	)
	(segment
		(start 318.265556 -290.94811)
		(end 318.038734 -291.496496)
		(width 0.18288)
		(layer "In2.Cu")
		(net "M_A_CPU0_SA_DQS_DP<6>")
	)
	(segment
		(start 314.93587 -301.84471)
		(end 314.656216 -302.124618)
		(width 0.18288)
		(layer "In2.Cu")
		(net "M_A_CPU0_SA_DQS_DP<6>")
	)
	(segment
		(start 316.57925 -295.020746)
		(end 316.364366 -295.539922)
		(width 0.18288)
		(layer "In2.Cu")
		(net "M_A_CPU0_SA_DQS_DP<6>")
	)
	(segment
		(start 324.312026 -280.446988)
		(end 323.296534 -282.89885)
		(width 0.18288)
		(layer "In2.Cu")
		(net "M_A_CPU0_SA_DQS_DP<6>")
	)
	(segment
		(start 318.570864 -290.211002)
		(end 318.40805 -290.278566)
		(width 0.18288)
		(layer "In2.Cu")
		(net "M_A_CPU0_SA_DQS_DP<6>")
	)
	(segment
		(start 337.887564 -270.521938)
		(end 337.878674 -270.516858)
		(width 0.088646)
		(layer "In2.Cu")
		(net "M_A_CPU0_SA_DQS_DP<6>")
	)
	(arc
		(start 337.417664 -269.707868)
		(mid 337.134962 -269.632126)
		(end 336.85226 -269.707868)
		(width 0.088646)
		(layer "In2.Cu")
		(net "M_A_CPU0_SA_DQS_DP<6>")
	)
	(arc
		(start 336.85226 -269.707868)
		(mid 336.665062 -269.758011)
		(end 336.477864 -269.707868)
		(width 0.088646)
		(layer "In2.Cu")
		(net "M_A_CPU0_SA_DQS_DP<6>")
	)
	(arc
		(start 338.44484 -270.25473)
		(mid 338.386721 -270.404971)
		(end 338.27085 -270.516858)
		(width 0.088646)
		(layer "In2.Cu")
		(net "M_A_CPU0_SA_DQS_DP<6>")
	)
	(arc
		(start 336.477864 -269.707868)
		(mid 336.195162 -269.632126)
		(end 335.91246 -269.707868)
		(width 0.088646)
		(layer "In2.Cu")
		(net "M_A_CPU0_SA_DQS_DP<6>")
	)
	(arc
		(start 334.973168 -269.708376)
		(mid 334.882626 -269.745879)
		(end 334.785462 -269.758668)
		(width 0.088646)
		(layer "In2.Cu")
		(net "M_A_CPU0_SA_DQS_DP<6>")
	)
	(arc
		(start 337.700112 -270.179038)
		(mid 337.61995 -269.906849)
		(end 337.417664 -269.707868)
		(width 0.088646)
		(layer "In2.Cu")
		(net "M_A_CPU0_SA_DQS_DP<6>")
	)
	(arc
		(start 338.26196 -270.521938)
		(mid 338.074762 -270.572081)
		(end 337.887564 -270.521938)
		(width 0.088646)
		(layer "In2.Cu")
		(net "M_A_CPU0_SA_DQS_DP<6>")
	)
	(arc
		(start 335.538064 -269.707868)
		(mid 335.255362 -269.632126)
		(end 334.97266 -269.707868)
		(width 0.088646)
		(layer "In2.Cu")
		(net "M_A_CPU0_SA_DQS_DP<6>")
	)
	(arc
		(start 335.91246 -269.707868)
		(mid 335.725262 -269.758011)
		(end 335.538064 -269.707868)
		(width 0.088646)
		(layer "In2.Cu")
		(net "M_A_CPU0_SA_DQS_DP<6>")
	)
	(arc
		(start 337.878674 -270.516858)
		(mid 337.74776 -270.380498)
		(end 337.700112 -270.19758)
		(width 0.088646)
		(layer "In2.Cu")
		(net "M_A_CPU0_SA_DQS_DP<6>")
	)
	(segment
		(start 307.768752 -310.79186)
		(end 310.070754 -310.79186)
		(width 0.1016)
		(layer "F.Cu")
		(net "M_A_CPU0_SA_DQS_DP<5>")
	)
	(segment
		(start 331.264514 -279.363932)
		(end 330.67498 -282.328366)
		(width 0.1524)
		(layer "F.Cu")
		(net "M_A_CPU0_SA_DQS_DP<5>")
	)
	(segment
		(start 310.088026 -310.780938)
		(end 310.395366 -310.780938)
		(width 0.20066)
		(layer "F.Cu")
		(net "M_A_CPU0_SA_DQS_DP<5>")
	)
	(segment
		(start 311.24144 -311.052972)
		(end 311.877456 -311.477914)
		(width 0.20066)
		(layer "F.Cu")
		(net "M_A_CPU0_SA_DQS_DP<5>")
	)
	(segment
		(start 306.17922 -311.477914)
		(end 306.40274 -311.477914)
		(width 0.20066)
		(layer "F.Cu")
		(net "M_A_CPU0_SA_DQS_DP<5>")
	)
	(segment
		(start 323.219572 -303.699926)
		(end 322.75399 -304.082196)
		(width 0.20066)
		(layer "F.Cu")
		(net "M_A_CPU0_SA_DQS_DP<5>")
	)
	(segment
		(start 330.67498 -282.328366)
		(end 330.67498 -295.887394)
		(width 0.1524)
		(layer "F.Cu")
		(net "M_A_CPU0_SA_DQS_DP<5>")
	)
	(segment
		(start 307.76291 -310.786018)
		(end 307.768752 -310.79186)
		(width 0.1016)
		(layer "F.Cu")
		(net "M_A_CPU0_SA_DQS_DP<5>")
	)
	(segment
		(start 320.490342 -306.101242)
		(end 320.025268 -306.483004)
		(width 0.20066)
		(layer "F.Cu")
		(net "M_A_CPU0_SA_DQS_DP<5>")
	)
	(segment
		(start 306.40274 -311.477914)
		(end 306.825142 -311.055512)
		(width 0.20066)
		(layer "F.Cu")
		(net "M_A_CPU0_SA_DQS_DP<5>")
	)
	(segment
		(start 323.859906 -303.335436)
		(end 323.394832 -303.717198)
		(width 0.20066)
		(layer "F.Cu")
		(net "M_A_CPU0_SA_DQS_DP<5>")
	)
	(segment
		(start 332.036928 -278.591264)
		(end 331.264514 -279.363678)
		(width 0.1524)
		(layer "F.Cu")
		(net "M_A_CPU0_SA_DQS_DP<5>")
	)
	(segment
		(start 322.096384 -304.621946)
		(end 321.630802 -305.004216)
		(width 0.20066)
		(layer "F.Cu")
		(net "M_A_CPU0_SA_DQS_DP<5>")
	)
	(segment
		(start 307.113178 -311.055512)
		(end 307.382672 -310.786018)
		(width 0.20066)
		(layer "F.Cu")
		(net "M_A_CPU0_SA_DQS_DP<5>")
	)
	(segment
		(start 313.531504 -311.216548)
		(end 313.53125 -311.216802)
		(width 0.20066)
		(layer "F.Cu")
		(net "M_A_CPU0_SA_DQS_DP<5>")
	)
	(segment
		(start 321.61353 -305.179222)
		(end 321.148456 -305.560984)
		(width 0.20066)
		(layer "F.Cu")
		(net "M_A_CPU0_SA_DQS_DP<5>")
	)
	(segment
		(start 330.073508 -297.17365)
		(end 329.84567 -297.401488)
		(width 0.1524)
		(layer "F.Cu")
		(net "M_A_CPU0_SA_DQS_DP<5>")
	)
	(segment
		(start 335.06664 -278.124158)
		(end 335.059274 -278.11984)
		(width 0.088646)
		(layer "F.Cu")
		(net "M_A_CPU0_SA_DQS_DP<5>")
	)
	(segment
		(start 322.75399 -304.082196)
		(end 322.736718 -304.257456)
		(width 0.20066)
		(layer "F.Cu")
		(net "M_A_CPU0_SA_DQS_DP<5>")
	)
	(segment
		(start 312.497216 -311.216802)
		(end 312.987182 -311.216802)
		(width 0.20066)
		(layer "F.Cu")
		(net "M_A_CPU0_SA_DQS_DP<5>")
	)
	(segment
		(start 330.257404 -296.898568)
		(end 330.073508 -297.17365)
		(width 0.1524)
		(layer "F.Cu")
		(net "M_A_CPU0_SA_DQS_DP<5>")
	)
	(segment
		(start 311.877456 -311.477914)
		(end 312.236104 -311.477914)
		(width 0.20066)
		(layer "F.Cu")
		(net "M_A_CPU0_SA_DQS_DP<5>")
	)
	(segment
		(start 334.043274 -277.304754)
		(end 334.03286 -277.31085)
		(width 0.088646)
		(layer "F.Cu")
		(net "M_A_CPU0_SA_DQS_DP<5>")
	)
	(segment
		(start 335.255362 -277.800562)
		(end 335.566258 -277.800562)
		(width 0.088646)
		(layer "F.Cu")
		(net "M_A_CPU0_SA_DQS_DP<5>")
	)
	(segment
		(start 307.382672 -310.786018)
		(end 307.76291 -310.786018)
		(width 0.20066)
		(layer "F.Cu")
		(net "M_A_CPU0_SA_DQS_DP<5>")
	)
	(segment
		(start 333.375762 -277.235158)
		(end 333.182722 -277.235158)
		(width 0.088646)
		(layer "F.Cu")
		(net "M_A_CPU0_SA_DQS_DP<5>")
	)
	(segment
		(start 318.639952 -307.619908)
		(end 315.224414 -311.0357)
		(width 0.20066)
		(layer "F.Cu")
		(net "M_A_CPU0_SA_DQS_DP<5>")
	)
	(segment
		(start 329.76693 -297.428412)
		(end 323.859906 -303.335436)
		(width 0.20066)
		(layer "F.Cu")
		(net "M_A_CPU0_SA_DQS_DP<5>")
	)
	(segment
		(start 319.850008 -306.465732)
		(end 319.384426 -306.848002)
		(width 0.20066)
		(layer "F.Cu")
		(net "M_A_CPU0_SA_DQS_DP<5>")
	)
	(segment
		(start 305.918108 -311.216802)
		(end 306.17922 -311.477914)
		(width 0.20066)
		(layer "F.Cu")
		(net "M_A_CPU0_SA_DQS_DP<5>")
	)
	(segment
		(start 310.070754 -310.79186)
		(end 310.081676 -310.780938)
		(width 0.1016)
		(layer "F.Cu")
		(net "M_A_CPU0_SA_DQS_DP<5>")
	)
	(segment
		(start 332.819756 -277.50389)
		(end 332.739746 -277.696676)
		(width 0.088646)
		(layer "F.Cu")
		(net "M_A_CPU0_SA_DQS_DP<5>")
	)
	(segment
		(start 332.052422 -278.57577)
		(end 332.036928 -278.591264)
		(width 0.088646)
		(layer "F.Cu")
		(net "M_A_CPU0_SA_DQS_DP<5>")
	)
	(segment
		(start 319.384426 -306.848002)
		(end 319.367154 -307.023008)
		(width 0.20066)
		(layer "F.Cu")
		(net "M_A_CPU0_SA_DQS_DP<5>")
	)
	(segment
		(start 323.394832 -303.717198)
		(end 323.219572 -303.699926)
		(width 0.20066)
		(layer "F.Cu")
		(net "M_A_CPU0_SA_DQS_DP<5>")
	)
	(segment
		(start 320.507614 -305.925982)
		(end 320.490342 -306.101242)
		(width 0.20066)
		(layer "F.Cu")
		(net "M_A_CPU0_SA_DQS_DP<5>")
	)
	(segment
		(start 330.67498 -295.887394)
		(end 330.257404 -296.898568)
		(width 0.1524)
		(layer "F.Cu")
		(net "M_A_CPU0_SA_DQS_DP<5>")
	)
	(segment
		(start 310.395366 -310.780938)
		(end 310.6674 -311.052972)
		(width 0.20066)
		(layer "F.Cu")
		(net "M_A_CPU0_SA_DQS_DP<5>")
	)
	(segment
		(start 314.160916 -311.475882)
		(end 313.790838 -311.475882)
		(width 0.20066)
		(layer "F.Cu")
		(net "M_A_CPU0_SA_DQS_DP<5>")
	)
	(segment
		(start 314.709556 -311.248298)
		(end 314.709048 -311.248552)
		(width 0.20066)
		(layer "F.Cu")
		(net "M_A_CPU0_SA_DQS_DP<5>")
	)
	(segment
		(start 321.630802 -305.004216)
		(end 321.61353 -305.179222)
		(width 0.20066)
		(layer "F.Cu")
		(net "M_A_CPU0_SA_DQS_DP<5>")
	)
	(segment
		(start 305.443382 -311.216802)
		(end 305.918108 -311.216802)
		(width 0.20066)
		(layer "F.Cu")
		(net "M_A_CPU0_SA_DQS_DP<5>")
	)
	(segment
		(start 332.277974 -278.158702)
		(end 332.161642 -278.511762)
		(width 0.088646)
		(layer "F.Cu")
		(net "M_A_CPU0_SA_DQS_DP<5>")
	)
	(segment
		(start 314.917582 -311.162446)
		(end 314.709556 -311.248298)
		(width 0.20066)
		(layer "F.Cu")
		(net "M_A_CPU0_SA_DQS_DP<5>")
	)
	(segment
		(start 333.02194 -277.301706)
		(end 332.819756 -277.50389)
		(width 0.088646)
		(layer "F.Cu")
		(net "M_A_CPU0_SA_DQS_DP<5>")
	)
	(segment
		(start 335.068164 -278.12492)
		(end 335.06664 -278.124158)
		(width 0.088646)
		(layer "F.Cu")
		(net "M_A_CPU0_SA_DQS_DP<5>")
	)
	(segment
		(start 310.6674 -311.052972)
		(end 311.24144 -311.052972)
		(width 0.20066)
		(layer "F.Cu")
		(net "M_A_CPU0_SA_DQS_DP<5>")
	)
	(segment
		(start 319.367154 -307.023008)
		(end 318.639952 -307.619908)
		(width 0.20066)
		(layer "F.Cu")
		(net "M_A_CPU0_SA_DQS_DP<5>")
	)
	(segment
		(start 310.081676 -310.780938)
		(end 310.088026 -310.780938)
		(width 0.1016)
		(layer "F.Cu")
		(net "M_A_CPU0_SA_DQS_DP<5>")
	)
	(segment
		(start 312.236104 -311.477914)
		(end 312.497216 -311.216802)
		(width 0.20066)
		(layer "F.Cu")
		(net "M_A_CPU0_SA_DQS_DP<5>")
	)
	(segment
		(start 332.097634 -278.57577)
		(end 332.052422 -278.57577)
		(width 0.088646)
		(layer "F.Cu")
		(net "M_A_CPU0_SA_DQS_DP<5>")
	)
	(segment
		(start 321.148456 -305.560984)
		(end 320.973196 -305.543712)
		(width 0.20066)
		(layer "F.Cu")
		(net "M_A_CPU0_SA_DQS_DP<5>")
	)
	(segment
		(start 333.182722 -277.235158)
		(end 333.02194 -277.301706)
		(width 0.088646)
		(layer "F.Cu")
		(net "M_A_CPU0_SA_DQS_DP<5>")
	)
	(segment
		(start 314.709048 -311.248552)
		(end 314.160916 -311.475882)
		(width 0.20066)
		(layer "F.Cu")
		(net "M_A_CPU0_SA_DQS_DP<5>")
	)
	(segment
		(start 306.825142 -311.055512)
		(end 307.113178 -311.055512)
		(width 0.20066)
		(layer "F.Cu")
		(net "M_A_CPU0_SA_DQS_DP<5>")
	)
	(segment
		(start 320.025268 -306.483004)
		(end 319.850008 -306.465732)
		(width 0.20066)
		(layer "F.Cu")
		(net "M_A_CPU0_SA_DQS_DP<5>")
	)
	(segment
		(start 313.53125 -311.216802)
		(end 312.987182 -311.216802)
		(width 0.20066)
		(layer "F.Cu")
		(net "M_A_CPU0_SA_DQS_DP<5>")
	)
	(segment
		(start 334.880712 -277.800562)
		(end 334.880712 -277.778464)
		(width 0.088646)
		(layer "F.Cu")
		(net "M_A_CPU0_SA_DQS_DP<5>")
	)
	(segment
		(start 313.790838 -311.475882)
		(end 313.531504 -311.216548)
		(width 0.20066)
		(layer "F.Cu")
		(net "M_A_CPU0_SA_DQS_DP<5>")
	)
	(segment
		(start 320.973196 -305.543712)
		(end 320.507614 -305.925982)
		(width 0.20066)
		(layer "F.Cu")
		(net "M_A_CPU0_SA_DQS_DP<5>")
	)
	(segment
		(start 332.161642 -278.511762)
		(end 332.097634 -278.57577)
		(width 0.088646)
		(layer "F.Cu")
		(net "M_A_CPU0_SA_DQS_DP<5>")
	)
	(segment
		(start 335.566258 -277.800562)
		(end 335.625186 -277.85949)
		(width 0.088646)
		(layer "F.Cu")
		(net "M_A_CPU0_SA_DQS_DP<5>")
	)
	(segment
		(start 329.84567 -297.401488)
		(end 329.793854 -297.401488)
		(width 0.1524)
		(layer "F.Cu")
		(net "M_A_CPU0_SA_DQS_DP<5>")
	)
	(segment
		(start 322.736718 -304.257456)
		(end 322.271644 -304.639218)
		(width 0.20066)
		(layer "F.Cu")
		(net "M_A_CPU0_SA_DQS_DP<5>")
	)
	(segment
		(start 329.793854 -297.401488)
		(end 329.76693 -297.428412)
		(width 0.1524)
		(layer "F.Cu")
		(net "M_A_CPU0_SA_DQS_DP<5>")
	)
	(segment
		(start 332.739746 -277.696676)
		(end 332.277974 -278.158702)
		(width 0.088646)
		(layer "F.Cu")
		(net "M_A_CPU0_SA_DQS_DP<5>")
	)
	(segment
		(start 322.271644 -304.639218)
		(end 322.096384 -304.621946)
		(width 0.20066)
		(layer "F.Cu")
		(net "M_A_CPU0_SA_DQS_DP<5>")
	)
	(segment
		(start 315.224414 -311.0357)
		(end 314.917582 -311.162446)
		(width 0.20066)
		(layer "F.Cu")
		(net "M_A_CPU0_SA_DQS_DP<5>")
	)
	(segment
		(start 331.264514 -279.363678)
		(end 331.264514 -279.363932)
		(width 0.1524)
		(layer "F.Cu")
		(net "M_A_CPU0_SA_DQS_DP<5>")
	)
	(segment
		(start 335.45145 -278.11984)
		(end 335.44256 -278.12492)
		(width 0.088646)
		(layer "F.Cu")
		(net "M_A_CPU0_SA_DQS_DP<5>")
	)
	(arc
		(start 334.880712 -277.778464)
		(mid 334.799801 -277.508336)
		(end 334.598518 -277.31085)
		(width 0.088646)
		(layer "F.Cu")
		(net "M_A_CPU0_SA_DQS_DP<5>")
	)
	(arc
		(start 334.03286 -277.31085)
		(mid 333.845662 -277.360993)
		(end 333.658464 -277.31085)
		(width 0.088646)
		(layer "F.Cu")
		(net "M_A_CPU0_SA_DQS_DP<5>")
	)
	(arc
		(start 333.658464 -277.31085)
		(mid 333.522098 -277.254372)
		(end 333.375762 -277.235158)
		(width 0.088646)
		(layer "F.Cu")
		(net "M_A_CPU0_SA_DQS_DP<5>")
	)
	(arc
		(start 335.44256 -278.12492)
		(mid 335.255362 -278.175063)
		(end 335.068164 -278.12492)
		(width 0.088646)
		(layer "F.Cu")
		(net "M_A_CPU0_SA_DQS_DP<5>")
	)
	(arc
		(start 335.625186 -277.85949)
		(mid 335.566843 -278.008713)
		(end 335.45145 -278.11984)
		(width 0.088646)
		(layer "F.Cu")
		(net "M_A_CPU0_SA_DQS_DP<5>")
	)
	(arc
		(start 334.598518 -277.31085)
		(mid 334.321705 -277.235014)
		(end 334.043274 -277.304754)
		(width 0.088646)
		(layer "F.Cu")
		(net "M_A_CPU0_SA_DQS_DP<5>")
	)
	(arc
		(start 335.059274 -278.11984)
		(mid 334.92836 -277.98348)
		(end 334.880712 -277.800562)
		(width 0.088646)
		(layer "F.Cu")
		(net "M_A_CPU0_SA_DQS_DP<5>")
	)
	(segment
		(start 314.248292 -275.941536)
		(end 311.75579 -275.941536)
		(width 0.1016)
		(layer "F.Cu")
		(net "M_A_CPU0_SA_DQS_DP<4>")
	)
	(segment
		(start 306.68468 -275.94179)
		(end 306.79644 -275.94179)
		(width 0.20066)
		(layer "F.Cu")
		(net "M_A_CPU0_SA_DQS_DP<4>")
	)
	(segment
		(start 330.385928 -262.912352)
		(end 324.860158 -268.438122)
		(width 0.1524)
		(layer "F.Cu")
		(net "M_A_CPU0_SA_DQS_DP<4>")
	)
	(segment
		(start 314.366402 -275.941536)
		(end 314.248292 -275.941536)
		(width 0.20066)
		(layer "F.Cu")
		(net "M_A_CPU0_SA_DQS_DP<4>")
	)
	(segment
		(start 307.80863 -275.255482)
		(end 308.077362 -275.255482)
		(width 0.20066)
		(layer "F.Cu")
		(net "M_A_CPU0_SA_DQS_DP<4>")
	)
	(segment
		(start 302.419512 -275.255482)
		(end 303.055528 -275.680678)
		(width 0.20066)
		(layer "F.Cu")
		(net "M_A_CPU0_SA_DQS_DP<4>")
	)
	(segment
		(start 332.804262 -262.68807)
		(end 332.339696 -262.880348)
		(width 0.088646)
		(layer "F.Cu")
		(net "M_A_CPU0_SA_DQS_DP<4>")
	)
	(segment
		(start 309.63108 -275.265388)
		(end 309.379874 -275.516594)
		(width 0.20066)
		(layer "F.Cu")
		(net "M_A_CPU0_SA_DQS_DP<4>")
	)
	(segment
		(start 303.055528 -275.680678)
		(end 303.642522 -275.680678)
		(width 0.20066)
		(layer "F.Cu")
		(net "M_A_CPU0_SA_DQS_DP<4>")
	)
	(segment
		(start 314.507626 -275.800312)
		(end 314.366402 -275.941536)
		(width 0.20066)
		(layer "F.Cu")
		(net "M_A_CPU0_SA_DQS_DP<4>")
	)
	(segment
		(start 318.115442 -274.654264)
		(end 316.973458 -275.41728)
		(width 0.20066)
		(layer "F.Cu")
		(net "M_A_CPU0_SA_DQS_DP<4>")
	)
	(segment
		(start 307.057552 -275.680678)
		(end 307.211222 -275.680678)
		(width 0.20066)
		(layer "F.Cu")
		(net "M_A_CPU0_SA_DQS_DP<4>")
	)
	(segment
		(start 324.27926 -268.438122)
		(end 323.705982 -269.0114)
		(width 0.1524)
		(layer "F.Cu")
		(net "M_A_CPU0_SA_DQS_DP<4>")
	)
	(segment
		(start 333.121254 -262.636762)
		(end 332.863952 -262.68807)
		(width 0.088646)
		(layer "F.Cu")
		(net "M_A_CPU0_SA_DQS_DP<4>")
	)
	(segment
		(start 324.860158 -268.438122)
		(end 324.27926 -268.438122)
		(width 0.1524)
		(layer "F.Cu")
		(net "M_A_CPU0_SA_DQS_DP<4>")
	)
	(segment
		(start 303.903634 -275.94179)
		(end 303.976532 -275.94179)
		(width 0.20066)
		(layer "F.Cu")
		(net "M_A_CPU0_SA_DQS_DP<4>")
	)
	(segment
		(start 310.797702 -275.686774)
		(end 309.780432 -275.265388)
		(width 0.20066)
		(layer "F.Cu")
		(net "M_A_CPU0_SA_DQS_DP<4>")
	)
	(segment
		(start 308.338474 -275.516594)
		(end 308.887114 -275.516594)
		(width 0.20066)
		(layer "F.Cu")
		(net "M_A_CPU0_SA_DQS_DP<4>")
	)
	(segment
		(start 333.845662 -262.336534)
		(end 333.121254 -262.636762)
		(width 0.088646)
		(layer "F.Cu")
		(net "M_A_CPU0_SA_DQS_DP<4>")
	)
	(segment
		(start 316.04839 -275.800312)
		(end 314.507626 -275.800312)
		(width 0.20066)
		(layer "F.Cu")
		(net "M_A_CPU0_SA_DQS_DP<4>")
	)
	(segment
		(start 330.728574 -262.880348)
		(end 330.69657 -262.912352)
		(width 0.088646)
		(layer "F.Cu")
		(net "M_A_CPU0_SA_DQS_DP<4>")
	)
	(segment
		(start 323.705982 -269.0114)
		(end 323.705982 -269.063724)
		(width 0.1524)
		(layer "F.Cu")
		(net "M_A_CPU0_SA_DQS_DP<4>")
	)
	(segment
		(start 302.142398 -275.255482)
		(end 302.419512 -275.255482)
		(width 0.20066)
		(layer "F.Cu")
		(net "M_A_CPU0_SA_DQS_DP<4>")
	)
	(segment
		(start 303.976532 -275.94179)
		(end 306.68468 -275.94179)
		(width 0.1016)
		(layer "F.Cu")
		(net "M_A_CPU0_SA_DQS_DP<4>")
	)
	(segment
		(start 316.973458 -275.41728)
		(end 316.04839 -275.800312)
		(width 0.20066)
		(layer "F.Cu")
		(net "M_A_CPU0_SA_DQS_DP<4>")
	)
	(segment
		(start 309.780432 -275.265388)
		(end 309.63108 -275.265388)
		(width 0.20066)
		(layer "F.Cu")
		(net "M_A_CPU0_SA_DQS_DP<4>")
	)
	(segment
		(start 307.211222 -275.680678)
		(end 307.505354 -275.558758)
		(width 0.20066)
		(layer "F.Cu")
		(net "M_A_CPU0_SA_DQS_DP<4>")
	)
	(segment
		(start 306.79644 -275.94179)
		(end 307.057552 -275.680678)
		(width 0.20066)
		(layer "F.Cu")
		(net "M_A_CPU0_SA_DQS_DP<4>")
	)
	(segment
		(start 301.343314 -275.516594)
		(end 301.881286 -275.516594)
		(width 0.20066)
		(layer "F.Cu")
		(net "M_A_CPU0_SA_DQS_DP<4>")
	)
	(segment
		(start 301.881286 -275.516594)
		(end 302.142398 -275.255482)
		(width 0.20066)
		(layer "F.Cu")
		(net "M_A_CPU0_SA_DQS_DP<4>")
	)
	(segment
		(start 332.863952 -262.68807)
		(end 332.804262 -262.68807)
		(width 0.088646)
		(layer "F.Cu")
		(net "M_A_CPU0_SA_DQS_DP<4>")
	)
	(segment
		(start 311.354724 -275.686774)
		(end 310.797702 -275.686774)
		(width 0.20066)
		(layer "F.Cu")
		(net "M_A_CPU0_SA_DQS_DP<4>")
	)
	(segment
		(start 332.339696 -262.880348)
		(end 330.728574 -262.880348)
		(width 0.088646)
		(layer "F.Cu")
		(net "M_A_CPU0_SA_DQS_DP<4>")
	)
	(segment
		(start 311.75579 -275.941536)
		(end 311.609486 -275.941536)
		(width 0.20066)
		(layer "F.Cu")
		(net "M_A_CPU0_SA_DQS_DP<4>")
	)
	(segment
		(start 311.609486 -275.941536)
		(end 311.354724 -275.686774)
		(width 0.20066)
		(layer "F.Cu")
		(net "M_A_CPU0_SA_DQS_DP<4>")
	)
	(segment
		(start 330.69657 -262.912352)
		(end 330.674472 -262.912352)
		(width 0.088646)
		(layer "F.Cu")
		(net "M_A_CPU0_SA_DQS_DP<4>")
	)
	(segment
		(start 307.505354 -275.558758)
		(end 307.80863 -275.255482)
		(width 0.20066)
		(layer "F.Cu")
		(net "M_A_CPU0_SA_DQS_DP<4>")
	)
	(segment
		(start 308.077362 -275.255482)
		(end 308.338474 -275.516594)
		(width 0.20066)
		(layer "F.Cu")
		(net "M_A_CPU0_SA_DQS_DP<4>")
	)
	(segment
		(start 309.379874 -275.516594)
		(end 308.887114 -275.516594)
		(width 0.20066)
		(layer "F.Cu")
		(net "M_A_CPU0_SA_DQS_DP<4>")
	)
	(segment
		(start 323.679058 -269.090648)
		(end 318.115442 -274.654264)
		(width 0.20066)
		(layer "F.Cu")
		(net "M_A_CPU0_SA_DQS_DP<4>")
	)
	(segment
		(start 323.705982 -269.063724)
		(end 323.679058 -269.090648)
		(width 0.1524)
		(layer "F.Cu")
		(net "M_A_CPU0_SA_DQS_DP<4>")
	)
	(segment
		(start 303.642522 -275.680678)
		(end 303.903634 -275.94179)
		(width 0.20066)
		(layer "F.Cu")
		(net "M_A_CPU0_SA_DQS_DP<4>")
	)
	(segment
		(start 330.674472 -262.912352)
		(end 330.385928 -262.912352)
		(width 0.1524)
		(layer "F.Cu")
		(net "M_A_CPU0_SA_DQS_DP<4>")
	)
	(segment
		(start 322.931282 -282.160218)
		(end 320.306446 -284.785054)
		(width 0.20066)
		(layer "F.Cu")
		(net "M_A_CPU0_SA_DQS_DP<3>")
	)
	(segment
		(start 324.516496 -276.964648)
		(end 323.87032 -280.213562)
		(width 0.1524)
		(layer "F.Cu")
		(net "M_A_CPU0_SA_DQS_DP<3>")
	)
	(segment
		(start 333.845662 -267.219938)
		(end 333.376778 -267.349986)
		(width 0.088646)
		(layer "F.Cu")
		(net "M_A_CPU0_SA_DQS_DP<3>")
	)
	(segment
		(start 314.112656 -285.29153)
		(end 311.877964 -285.29153)
		(width 0.1016)
		(layer "F.Cu")
		(net "M_A_CPU0_SA_DQS_DP<3>")
	)
	(segment
		(start 308.338474 -284.866588)
		(end 308.887114 -284.866588)
		(width 0.20066)
		(layer "F.Cu")
		(net "M_A_CPU0_SA_DQS_DP<3>")
	)
	(segment
		(start 322.958206 -282.133294)
		(end 322.931282 -282.160218)
		(width 0.1524)
		(layer "F.Cu")
		(net "M_A_CPU0_SA_DQS_DP<3>")
	)
	(segment
		(start 314.50153 -285.298642)
		(end 314.12688 -285.298642)
		(width 0.20066)
		(layer "F.Cu")
		(net "M_A_CPU0_SA_DQS_DP<3>")
	)
	(segment
		(start 308.077362 -284.605476)
		(end 308.338474 -284.866588)
		(width 0.20066)
		(layer "F.Cu")
		(net "M_A_CPU0_SA_DQS_DP<3>")
	)
	(segment
		(start 304.319178 -285.301182)
		(end 304.328576 -285.291784)
		(width 0.1016)
		(layer "F.Cu")
		(net "M_A_CPU0_SA_DQS_DP<3>")
	)
	(segment
		(start 309.63108 -284.615382)
		(end 309.379874 -284.866588)
		(width 0.20066)
		(layer "F.Cu")
		(net "M_A_CPU0_SA_DQS_DP<3>")
	)
	(segment
		(start 310.946292 -285.036768)
		(end 309.929022 -284.615382)
		(width 0.20066)
		(layer "F.Cu")
		(net "M_A_CPU0_SA_DQS_DP<3>")
	)
	(segment
		(start 307.100224 -285.030672)
		(end 307.492146 -285.030672)
		(width 0.20066)
		(layer "F.Cu")
		(net "M_A_CPU0_SA_DQS_DP<3>")
	)
	(segment
		(start 314.119768 -285.298642)
		(end 314.112656 -285.29153)
		(width 0.1016)
		(layer "F.Cu")
		(net "M_A_CPU0_SA_DQS_DP<3>")
	)
	(segment
		(start 311.84088 -285.309564)
		(end 311.445656 -285.309564)
		(width 0.20066)
		(layer "F.Cu")
		(net "M_A_CPU0_SA_DQS_DP<3>")
	)
	(segment
		(start 306.644294 -285.291784)
		(end 306.839112 -285.291784)
		(width 0.20066)
		(layer "F.Cu")
		(net "M_A_CPU0_SA_DQS_DP<3>")
	)
	(segment
		(start 306.839112 -285.291784)
		(end 307.100224 -285.030672)
		(width 0.20066)
		(layer "F.Cu")
		(net "M_A_CPU0_SA_DQS_DP<3>")
	)
	(segment
		(start 322.958206 -282.080716)
		(end 322.958206 -282.133294)
		(width 0.1524)
		(layer "F.Cu")
		(net "M_A_CPU0_SA_DQS_DP<3>")
	)
	(segment
		(start 301.343314 -284.866588)
		(end 301.881286 -284.866588)
		(width 0.20066)
		(layer "F.Cu")
		(net "M_A_CPU0_SA_DQS_DP<3>")
	)
	(segment
		(start 331.866494 -268.64183)
		(end 331.589126 -268.756892)
		(width 0.088646)
		(layer "F.Cu")
		(net "M_A_CPU0_SA_DQS_DP<3>")
	)
	(segment
		(start 311.17286 -285.036768)
		(end 310.946292 -285.036768)
		(width 0.20066)
		(layer "F.Cu")
		(net "M_A_CPU0_SA_DQS_DP<3>")
	)
	(segment
		(start 314.553346 -285.246826)
		(end 314.50153 -285.298642)
		(width 0.20066)
		(layer "F.Cu")
		(net "M_A_CPU0_SA_DQS_DP<3>")
	)
	(segment
		(start 325.7677 -274.624038)
		(end 324.516496 -276.964648)
		(width 0.1524)
		(layer "F.Cu")
		(net "M_A_CPU0_SA_DQS_DP<3>")
	)
	(segment
		(start 323.87032 -280.213562)
		(end 323.285104 -281.753818)
		(width 0.1524)
		(layer "F.Cu")
		(net "M_A_CPU0_SA_DQS_DP<3>")
	)
	(segment
		(start 311.877964 -285.29153)
		(end 311.85993 -285.309564)
		(width 0.1016)
		(layer "F.Cu")
		(net "M_A_CPU0_SA_DQS_DP<3>")
	)
	(segment
		(start 307.917342 -284.605476)
		(end 308.077362 -284.605476)
		(width 0.20066)
		(layer "F.Cu")
		(net "M_A_CPU0_SA_DQS_DP<3>")
	)
	(segment
		(start 302.142398 -284.605476)
		(end 302.606202 -284.605476)
		(width 0.20066)
		(layer "F.Cu")
		(net "M_A_CPU0_SA_DQS_DP<3>")
	)
	(segment
		(start 314.12688 -285.298642)
		(end 314.119768 -285.298642)
		(width 0.1016)
		(layer "F.Cu")
		(net "M_A_CPU0_SA_DQS_DP<3>")
	)
	(segment
		(start 307.492146 -285.030672)
		(end 307.917342 -284.605476)
		(width 0.20066)
		(layer "F.Cu")
		(net "M_A_CPU0_SA_DQS_DP<3>")
	)
	(segment
		(start 303.638458 -285.030672)
		(end 303.908968 -285.301182)
		(width 0.20066)
		(layer "F.Cu")
		(net "M_A_CPU0_SA_DQS_DP<3>")
	)
	(segment
		(start 304.328576 -285.291784)
		(end 306.636928 -285.291784)
		(width 0.1016)
		(layer "F.Cu")
		(net "M_A_CPU0_SA_DQS_DP<3>")
	)
	(segment
		(start 303.908968 -285.301182)
		(end 304.319178 -285.301182)
		(width 0.20066)
		(layer "F.Cu")
		(net "M_A_CPU0_SA_DQS_DP<3>")
	)
	(segment
		(start 331.046074 -269.345664)
		(end 325.7677 -274.624038)
		(width 0.1524)
		(layer "F.Cu")
		(net "M_A_CPU0_SA_DQS_DP<3>")
	)
	(segment
		(start 306.636928 -285.291784)
		(end 306.644294 -285.291784)
		(width 0.101854)
		(layer "F.Cu")
		(net "M_A_CPU0_SA_DQS_DP<3>")
	)
	(segment
		(start 331.061568 -269.28445)
		(end 331.061568 -269.33017)
		(width 0.088646)
		(layer "F.Cu")
		(net "M_A_CPU0_SA_DQS_DP<3>")
	)
	(segment
		(start 332.83017 -267.6779)
		(end 331.866494 -268.64183)
		(width 0.088646)
		(layer "F.Cu")
		(net "M_A_CPU0_SA_DQS_DP<3>")
	)
	(segment
		(start 311.445656 -285.309564)
		(end 311.17286 -285.036768)
		(width 0.20066)
		(layer "F.Cu")
		(net "M_A_CPU0_SA_DQS_DP<3>")
	)
	(segment
		(start 309.929022 -284.615382)
		(end 309.63108 -284.615382)
		(width 0.20066)
		(layer "F.Cu")
		(net "M_A_CPU0_SA_DQS_DP<3>")
	)
	(segment
		(start 303.242218 -285.030672)
		(end 303.638458 -285.030672)
		(width 0.20066)
		(layer "F.Cu")
		(net "M_A_CPU0_SA_DQS_DP<3>")
	)
	(segment
		(start 331.061568 -269.33017)
		(end 331.046074 -269.345664)
		(width 0.088646)
		(layer "F.Cu")
		(net "M_A_CPU0_SA_DQS_DP<3>")
	)
	(segment
		(start 301.881286 -284.866588)
		(end 302.142398 -284.605476)
		(width 0.20066)
		(layer "F.Cu")
		(net "M_A_CPU0_SA_DQS_DP<3>")
	)
	(segment
		(start 331.589126 -268.756892)
		(end 331.061568 -269.28445)
		(width 0.088646)
		(layer "F.Cu")
		(net "M_A_CPU0_SA_DQS_DP<3>")
	)
	(segment
		(start 311.85993 -285.309564)
		(end 311.84088 -285.309564)
		(width 0.1016)
		(layer "F.Cu")
		(net "M_A_CPU0_SA_DQS_DP<3>")
	)
	(segment
		(start 333.376778 -267.349986)
		(end 332.83017 -267.6779)
		(width 0.088646)
		(layer "F.Cu")
		(net "M_A_CPU0_SA_DQS_DP<3>")
	)
	(segment
		(start 320.306446 -284.785054)
		(end 317.98387 -285.246826)
		(width 0.20066)
		(layer "F.Cu")
		(net "M_A_CPU0_SA_DQS_DP<3>")
	)
	(segment
		(start 302.606202 -284.605476)
		(end 303.242218 -285.030672)
		(width 0.20066)
		(layer "F.Cu")
		(net "M_A_CPU0_SA_DQS_DP<3>")
	)
	(segment
		(start 317.98387 -285.246826)
		(end 314.553346 -285.246826)
		(width 0.20066)
		(layer "F.Cu")
		(net "M_A_CPU0_SA_DQS_DP<3>")
	)
	(segment
		(start 309.379874 -284.866588)
		(end 308.887114 -284.866588)
		(width 0.20066)
		(layer "F.Cu")
		(net "M_A_CPU0_SA_DQS_DP<3>")
	)
	(segment
		(start 323.285104 -281.753818)
		(end 322.958206 -282.080716)
		(width 0.1524)
		(layer "F.Cu")
		(net "M_A_CPU0_SA_DQS_DP<3>")
	)
	(segment
		(start 327.38695 -291.235384)
		(end 327.360026 -291.262308)
		(width 0.1524)
		(layer "F.Cu")
		(net "M_A_CPU0_SA_DQS_DP<2>")
	)
	(segment
		(start 309.6514 -293.945056)
		(end 309.379874 -294.216582)
		(width 0.20066)
		(layer "F.Cu")
		(net "M_A_CPU0_SA_DQS_DP<2>")
	)
	(segment
		(start 303.242218 -294.380666)
		(end 303.638458 -294.380666)
		(width 0.20066)
		(layer "F.Cu")
		(net "M_A_CPU0_SA_DQS_DP<2>")
	)
	(segment
		(start 327.360026 -291.262308)
		(end 324.997064 -293.62527)
		(width 0.20066)
		(layer "F.Cu")
		(net "M_A_CPU0_SA_DQS_DP<2>")
	)
	(segment
		(start 332.348586 -273.385026)
		(end 331.94625 -273.986498)
		(width 0.088646)
		(layer "F.Cu")
		(net "M_A_CPU0_SA_DQS_DP<2>")
	)
	(segment
		(start 331.564742 -274.461478)
		(end 328.928222 -277.097998)
		(width 0.1524)
		(layer "F.Cu")
		(net "M_A_CPU0_SA_DQS_DP<2>")
	)
	(segment
		(start 332.56093 -273.224498)
		(end 332.471776 -273.261328)
		(width 0.088646)
		(layer "F.Cu")
		(net "M_A_CPU0_SA_DQS_DP<2>")
	)
	(segment
		(start 306.644294 -294.649144)
		(end 306.973986 -294.649144)
		(width 0.20066)
		(layer "F.Cu")
		(net "M_A_CPU0_SA_DQS_DP<2>")
	)
	(segment
		(start 333.845662 -272.103342)
		(end 333.763112 -272.302732)
		(width 0.088646)
		(layer "F.Cu")
		(net "M_A_CPU0_SA_DQS_DP<2>")
	)
	(segment
		(start 301.343314 -294.216582)
		(end 301.881286 -294.216582)
		(width 0.20066)
		(layer "F.Cu")
		(net "M_A_CPU0_SA_DQS_DP<2>")
	)
	(segment
		(start 331.94625 -273.986498)
		(end 331.727302 -274.253198)
		(width 0.088646)
		(layer "F.Cu")
		(net "M_A_CPU0_SA_DQS_DP<2>")
	)
	(segment
		(start 307.492146 -294.380666)
		(end 307.917342 -293.95547)
		(width 0.20066)
		(layer "F.Cu")
		(net "M_A_CPU0_SA_DQS_DP<2>")
	)
	(segment
		(start 311.84088 -294.678608)
		(end 311.672986 -294.678608)
		(width 0.20066)
		(layer "F.Cu")
		(net "M_A_CPU0_SA_DQS_DP<2>")
	)
	(segment
		(start 303.638458 -294.380666)
		(end 303.908968 -294.651176)
		(width 0.20066)
		(layer "F.Cu")
		(net "M_A_CPU0_SA_DQS_DP<2>")
	)
	(segment
		(start 309.379874 -294.216582)
		(end 308.887114 -294.216582)
		(width 0.20066)
		(layer "F.Cu")
		(net "M_A_CPU0_SA_DQS_DP<2>")
	)
	(segment
		(start 304.328576 -294.641778)
		(end 306.636928 -294.641778)
		(width 0.1016)
		(layer "F.Cu")
		(net "M_A_CPU0_SA_DQS_DP<2>")
	)
	(segment
		(start 332.918308 -273.189192)
		(end 332.914498 -273.187414)
		(width 0.088646)
		(layer "F.Cu")
		(net "M_A_CPU0_SA_DQS_DP<2>")
	)
	(segment
		(start 308.338474 -294.216582)
		(end 308.887114 -294.216582)
		(width 0.20066)
		(layer "F.Cu")
		(net "M_A_CPU0_SA_DQS_DP<2>")
	)
	(segment
		(start 327.62698 -290.942776)
		(end 327.38695 -291.182806)
		(width 0.1524)
		(layer "F.Cu")
		(net "M_A_CPU0_SA_DQS_DP<2>")
	)
	(segment
		(start 309.817516 -293.945056)
		(end 309.6514 -293.945056)
		(width 0.20066)
		(layer "F.Cu")
		(net "M_A_CPU0_SA_DQS_DP<2>")
	)
	(segment
		(start 302.142398 -293.95547)
		(end 302.606202 -293.95547)
		(width 0.20066)
		(layer "F.Cu")
		(net "M_A_CPU0_SA_DQS_DP<2>")
	)
	(segment
		(start 311.023762 -294.444674)
		(end 309.817516 -293.945056)
		(width 0.20066)
		(layer "F.Cu")
		(net "M_A_CPU0_SA_DQS_DP<2>")
	)
	(segment
		(start 306.973986 -294.649144)
		(end 307.242464 -294.380666)
		(width 0.20066)
		(layer "F.Cu")
		(net "M_A_CPU0_SA_DQS_DP<2>")
	)
	(segment
		(start 314.17768 -294.641524)
		(end 312.097674 -294.641524)
		(width 0.1016)
		(layer "F.Cu")
		(net "M_A_CPU0_SA_DQS_DP<2>")
	)
	(segment
		(start 302.606202 -293.95547)
		(end 303.242218 -294.380666)
		(width 0.20066)
		(layer "F.Cu")
		(net "M_A_CPU0_SA_DQS_DP<2>")
	)
	(segment
		(start 333.763112 -272.302732)
		(end 333.763112 -272.798032)
		(width 0.088646)
		(layer "F.Cu")
		(net "M_A_CPU0_SA_DQS_DP<2>")
	)
	(segment
		(start 308.077362 -293.95547)
		(end 308.338474 -294.216582)
		(width 0.20066)
		(layer "F.Cu")
		(net "M_A_CPU0_SA_DQS_DP<2>")
	)
	(segment
		(start 328.305668 -278.26335)
		(end 327.62698 -281.65679)
		(width 0.1524)
		(layer "F.Cu")
		(net "M_A_CPU0_SA_DQS_DP<2>")
	)
	(segment
		(start 327.38695 -291.182806)
		(end 327.38695 -291.235384)
		(width 0.1524)
		(layer "F.Cu")
		(net "M_A_CPU0_SA_DQS_DP<2>")
	)
	(segment
		(start 327.62698 -281.65679)
		(end 327.62698 -290.942776)
		(width 0.1524)
		(layer "F.Cu")
		(net "M_A_CPU0_SA_DQS_DP<2>")
	)
	(segment
		(start 333.077566 -273.254978)
		(end 332.918308 -273.189192)
		(width 0.088646)
		(layer "F.Cu")
		(net "M_A_CPU0_SA_DQS_DP<2>")
	)
	(segment
		(start 306.636928 -294.641778)
		(end 306.644294 -294.649144)
		(width 0.1016)
		(layer "F.Cu")
		(net "M_A_CPU0_SA_DQS_DP<2>")
	)
	(segment
		(start 311.923176 -294.678608)
		(end 311.84088 -294.678608)
		(width 0.1016)
		(layer "F.Cu")
		(net "M_A_CPU0_SA_DQS_DP<2>")
	)
	(segment
		(start 332.914498 -273.187414)
		(end 332.650338 -273.187414)
		(width 0.088646)
		(layer "F.Cu")
		(net "M_A_CPU0_SA_DQS_DP<2>")
	)
	(segment
		(start 332.471776 -273.261328)
		(end 332.348586 -273.385026)
		(width 0.088646)
		(layer "F.Cu")
		(net "M_A_CPU0_SA_DQS_DP<2>")
	)
	(segment
		(start 322.54317 -294.641524)
		(end 314.17768 -294.641524)
		(width 0.20066)
		(layer "F.Cu")
		(net "M_A_CPU0_SA_DQS_DP<2>")
	)
	(segment
		(start 328.928222 -277.097998)
		(end 328.305668 -278.26335)
		(width 0.1524)
		(layer "F.Cu")
		(net "M_A_CPU0_SA_DQS_DP<2>")
	)
	(segment
		(start 311.439052 -294.444674)
		(end 311.023762 -294.444674)
		(width 0.20066)
		(layer "F.Cu")
		(net "M_A_CPU0_SA_DQS_DP<2>")
	)
	(segment
		(start 331.727302 -274.253198)
		(end 331.580236 -274.400264)
		(width 0.088646)
		(layer "F.Cu")
		(net "M_A_CPU0_SA_DQS_DP<2>")
	)
	(segment
		(start 312.097674 -294.641524)
		(end 311.923176 -294.678608)
		(width 0.1016)
		(layer "F.Cu")
		(net "M_A_CPU0_SA_DQS_DP<2>")
	)
	(segment
		(start 331.580236 -274.445984)
		(end 331.564742 -274.461478)
		(width 0.088646)
		(layer "F.Cu")
		(net "M_A_CPU0_SA_DQS_DP<2>")
	)
	(segment
		(start 332.650338 -273.187414)
		(end 332.56093 -273.224498)
		(width 0.088646)
		(layer "F.Cu")
		(net "M_A_CPU0_SA_DQS_DP<2>")
	)
	(segment
		(start 324.997064 -293.62527)
		(end 322.54317 -294.641524)
		(width 0.20066)
		(layer "F.Cu")
		(net "M_A_CPU0_SA_DQS_DP<2>")
	)
	(segment
		(start 304.319178 -294.651176)
		(end 304.328576 -294.641778)
		(width 0.1016)
		(layer "F.Cu")
		(net "M_A_CPU0_SA_DQS_DP<2>")
	)
	(segment
		(start 311.672986 -294.678608)
		(end 311.439052 -294.444674)
		(width 0.20066)
		(layer "F.Cu")
		(net "M_A_CPU0_SA_DQS_DP<2>")
	)
	(segment
		(start 303.908968 -294.651176)
		(end 304.319178 -294.651176)
		(width 0.20066)
		(layer "F.Cu")
		(net "M_A_CPU0_SA_DQS_DP<2>")
	)
	(segment
		(start 301.881286 -294.216582)
		(end 302.142398 -293.95547)
		(width 0.20066)
		(layer "F.Cu")
		(net "M_A_CPU0_SA_DQS_DP<2>")
	)
	(segment
		(start 307.917342 -293.95547)
		(end 308.077362 -293.95547)
		(width 0.20066)
		(layer "F.Cu")
		(net "M_A_CPU0_SA_DQS_DP<2>")
	)
	(segment
		(start 333.40167 -273.254978)
		(end 333.077566 -273.254978)
		(width 0.088646)
		(layer "F.Cu")
		(net "M_A_CPU0_SA_DQS_DP<2>")
	)
	(segment
		(start 331.580236 -274.400264)
		(end 331.580236 -274.445984)
		(width 0.088646)
		(layer "F.Cu")
		(net "M_A_CPU0_SA_DQS_DP<2>")
	)
	(segment
		(start 307.242464 -294.380666)
		(end 307.492146 -294.380666)
		(width 0.20066)
		(layer "F.Cu")
		(net "M_A_CPU0_SA_DQS_DP<2>")
	)
	(arc
		(start 333.616046 -273.164046)
		(mid 333.518115 -273.231355)
		(end 333.40167 -273.254978)
		(width 0.088646)
		(layer "F.Cu")
		(net "M_A_CPU0_SA_DQS_DP<2>")
	)
	(arc
		(start 333.763112 -272.798032)
		(mid 333.725066 -272.9953)
		(end 333.616046 -273.164046)
		(width 0.088646)
		(layer "F.Cu")
		(net "M_A_CPU0_SA_DQS_DP<2>")
	)
	(segment
		(start 307.383434 -303.73066)
		(end 307.057552 -303.73066)
		(width 0.20066)
		(layer "F.Cu")
		(net "M_A_CPU0_SA_DQS_DP<1>")
	)
	(segment
		(start 303.203356 -303.73066)
		(end 302.56734 -303.305464)
		(width 0.20066)
		(layer "F.Cu")
		(net "M_A_CPU0_SA_DQS_DP<1>")
	)
	(segment
		(start 307.057552 -303.73066)
		(end 306.79644 -303.991772)
		(width 0.20066)
		(layer "F.Cu")
		(net "M_A_CPU0_SA_DQS_DP<1>")
	)
	(segment
		(start 303.830482 -303.73066)
		(end 303.203356 -303.73066)
		(width 0.20066)
		(layer "F.Cu")
		(net "M_A_CPU0_SA_DQS_DP<1>")
	)
	(segment
		(start 302.142398 -303.305464)
		(end 301.881286 -303.566576)
		(width 0.20066)
		(layer "F.Cu")
		(net "M_A_CPU0_SA_DQS_DP<1>")
	)
	(segment
		(start 306.320952 -303.991772)
		(end 304.565558 -303.991772)
		(width 0.1016)
		(layer "F.Cu")
		(net "M_A_CPU0_SA_DQS_DP<1>")
	)
	(segment
		(start 308.338474 -303.566576)
		(end 308.077362 -303.305464)
		(width 0.20066)
		(layer "F.Cu")
		(net "M_A_CPU0_SA_DQS_DP<1>")
	)
	(segment
		(start 337.134962 -269.66164)
		(end 337.134962 -270.19758)
		(width 0.20066)
		(layer "F.Cu")
		(net "M_A_CPU0_SA_DQS_DP<1>")
	)
	(segment
		(start 308.887114 -303.566576)
		(end 308.338474 -303.566576)
		(width 0.20066)
		(layer "F.Cu")
		(net "M_A_CPU0_SA_DQS_DP<1>")
	)
	(segment
		(start 301.881286 -303.566576)
		(end 301.343314 -303.566576)
		(width 0.20066)
		(layer "F.Cu")
		(net "M_A_CPU0_SA_DQS_DP<1>")
	)
	(segment
		(start 304.328576 -303.991772)
		(end 304.319178 -304.00117)
		(width 0.101854)
		(layer "F.Cu")
		(net "M_A_CPU0_SA_DQS_DP<1>")
	)
	(segment
		(start 307.80863 -303.305464)
		(end 307.383434 -303.73066)
		(width 0.20066)
		(layer "F.Cu")
		(net "M_A_CPU0_SA_DQS_DP<1>")
	)
	(segment
		(start 304.319178 -304.00117)
		(end 304.100992 -304.00117)
		(width 0.20066)
		(layer "F.Cu")
		(net "M_A_CPU0_SA_DQS_DP<1>")
	)
	(segment
		(start 309.992014 -303.566576)
		(end 308.887114 -303.566576)
		(width 0.20066)
		(layer "F.Cu")
		(net "M_A_CPU0_SA_DQS_DP<1>")
	)
	(segment
		(start 304.565558 -303.991772)
		(end 304.328576 -303.991772)
		(width 0.101854)
		(layer "F.Cu")
		(net "M_A_CPU0_SA_DQS_DP<1>")
	)
	(segment
		(start 306.644294 -303.991772)
		(end 306.320952 -303.991772)
		(width 0.101854)
		(layer "F.Cu")
		(net "M_A_CPU0_SA_DQS_DP<1>")
	)
	(segment
		(start 308.077362 -303.305464)
		(end 307.80863 -303.305464)
		(width 0.20066)
		(layer "F.Cu")
		(net "M_A_CPU0_SA_DQS_DP<1>")
	)
	(segment
		(start 304.100992 -304.00117)
		(end 303.830482 -303.73066)
		(width 0.20066)
		(layer "F.Cu")
		(net "M_A_CPU0_SA_DQS_DP<1>")
	)
	(segment
		(start 306.79644 -303.991772)
		(end 306.644294 -303.991772)
		(width 0.20066)
		(layer "F.Cu")
		(net "M_A_CPU0_SA_DQS_DP<1>")
	)
	(segment
		(start 302.56734 -303.305464)
		(end 302.142398 -303.305464)
		(width 0.20066)
		(layer "F.Cu")
		(net "M_A_CPU0_SA_DQS_DP<1>")
	)
	(segment
		(start 315.917834 -302.65751)
		(end 314.855606 -303.719738)
		(width 0.18288)
		(layer "In2.Cu")
		(net "M_A_CPU0_SA_DQS_DP<1>")
	)
	(segment
		(start 337.134962 -270.19758)
		(end 336.793332 -270.288004)
		(width 0.088646)
		(layer "In2.Cu")
		(net "M_A_CPU0_SA_DQS_DP<1>")
	)
	(segment
		(start 312.308494 -303.590452)
		(end 312.098182 -303.38014)
		(width 0.18288)
		(layer "In2.Cu")
		(net "M_A_CPU0_SA_DQS_DP<1>")
	)
	(segment
		(start 329.414632 -276.800564)
		(end 325.421244 -280.793952)
		(width 0.18288)
		(layer "In2.Cu")
		(net "M_A_CPU0_SA_DQS_DP<1>")
	)
	(segment
		(start 312.069988 -303.351946)
		(end 312.069988 -303.336198)
		(width 0.16002)
		(layer "In2.Cu")
		(net "M_A_CPU0_SA_DQS_DP<1>")
	)
	(segment
		(start 325.421244 -280.793952)
		(end 325.341488 -280.986484)
		(width 0.18288)
		(layer "In2.Cu")
		(net "M_A_CPU0_SA_DQS_DP<1>")
	)
	(segment
		(start 332.783688 -271.626076)
		(end 330.688188 -273.722084)
		(width 0.18288)
		(layer "In2.Cu")
		(net "M_A_CPU0_SA_DQS_DP<1>")
	)
	(segment
		(start 314.550044 -303.719738)
		(end 314.278264 -303.991518)
		(width 0.18288)
		(layer "In2.Cu")
		(net "M_A_CPU0_SA_DQS_DP<1>")
	)
	(segment
		(start 311.869836 -303.136046)
		(end 311.854088 -303.136046)
		(width 0.16002)
		(layer "In2.Cu")
		(net "M_A_CPU0_SA_DQS_DP<1>")
	)
	(segment
		(start 336.793332 -270.288004)
		(end 336.369406 -270.52905)
		(width 0.088646)
		(layer "In2.Cu")
		(net "M_A_CPU0_SA_DQS_DP<1>")
	)
	(segment
		(start 321.600068 -286.218122)
		(end 316.868302 -297.632374)
		(width 0.18288)
		(layer "In2.Cu")
		(net "M_A_CPU0_SA_DQS_DP<1>")
	)
	(segment
		(start 313.906662 -303.991518)
		(end 313.620404 -303.70526)
		(width 0.18288)
		(layer "In2.Cu")
		(net "M_A_CPU0_SA_DQS_DP<1>")
	)
	(segment
		(start 311.018428 -302.94707)
		(end 310.651144 -303.314354)
		(width 0.18288)
		(layer "In2.Cu")
		(net "M_A_CPU0_SA_DQS_DP<1>")
	)
	(segment
		(start 333.044038 -271.281398)
		(end 333.044038 -271.365726)
		(width 0.088646)
		(layer "In2.Cu")
		(net "M_A_CPU0_SA_DQS_DP<1>")
	)
	(segment
		(start 312.098182 -303.38014)
		(end 312.069988 -303.351946)
		(width 0.16002)
		(layer "In2.Cu")
		(net "M_A_CPU0_SA_DQS_DP<1>")
	)
	(segment
		(start 312.069988 -303.336198)
		(end 311.869836 -303.136046)
		(width 0.16002)
		(layer "In2.Cu")
		(net "M_A_CPU0_SA_DQS_DP<1>")
	)
	(segment
		(start 333.155036 -271.1704)
		(end 333.044038 -271.281398)
		(width 0.088646)
		(layer "In2.Cu")
		(net "M_A_CPU0_SA_DQS_DP<1>")
	)
	(segment
		(start 311.854088 -303.136046)
		(end 311.825894 -303.107852)
		(width 0.16002)
		(layer "In2.Cu")
		(net "M_A_CPU0_SA_DQS_DP<1>")
	)
	(segment
		(start 334.096106 -271.1704)
		(end 333.155036 -271.1704)
		(width 0.088646)
		(layer "In2.Cu")
		(net "M_A_CPU0_SA_DQS_DP<1>")
	)
	(segment
		(start 325.341488 -280.986484)
		(end 324.286626 -283.531564)
		(width 0.18288)
		(layer "In2.Cu")
		(net "M_A_CPU0_SA_DQS_DP<1>")
	)
	(segment
		(start 310.244236 -303.314354)
		(end 309.992014 -303.566576)
		(width 0.18288)
		(layer "In2.Cu")
		(net "M_A_CPU0_SA_DQS_DP<1>")
	)
	(segment
		(start 324.286626 -283.531564)
		(end 321.600068 -286.218122)
		(width 0.18288)
		(layer "In2.Cu")
		(net "M_A_CPU0_SA_DQS_DP<1>")
	)
	(segment
		(start 336.131916 -270.603726)
		(end 335.682336 -270.603726)
		(width 0.088646)
		(layer "In2.Cu")
		(net "M_A_CPU0_SA_DQS_DP<1>")
	)
	(segment
		(start 334.520286 -270.74622)
		(end 334.096106 -271.1704)
		(width 0.088646)
		(layer "In2.Cu")
		(net "M_A_CPU0_SA_DQS_DP<1>")
	)
	(segment
		(start 312.585608 -303.70526)
		(end 312.308494 -303.590452)
		(width 0.18288)
		(layer "In2.Cu")
		(net "M_A_CPU0_SA_DQS_DP<1>")
	)
	(segment
		(start 311.825894 -303.107852)
		(end 311.665112 -302.94707)
		(width 0.18288)
		(layer "In2.Cu")
		(net "M_A_CPU0_SA_DQS_DP<1>")
	)
	(segment
		(start 313.620404 -303.70526)
		(end 312.585608 -303.70526)
		(width 0.18288)
		(layer "In2.Cu")
		(net "M_A_CPU0_SA_DQS_DP<1>")
	)
	(segment
		(start 330.688188 -273.722084)
		(end 329.414632 -276.800564)
		(width 0.18288)
		(layer "In2.Cu")
		(net "M_A_CPU0_SA_DQS_DP<1>")
	)
	(segment
		(start 310.651144 -303.314354)
		(end 310.244236 -303.314354)
		(width 0.18288)
		(layer "In2.Cu")
		(net "M_A_CPU0_SA_DQS_DP<1>")
	)
	(segment
		(start 314.855606 -303.719738)
		(end 314.550044 -303.719738)
		(width 0.18288)
		(layer "In2.Cu")
		(net "M_A_CPU0_SA_DQS_DP<1>")
	)
	(segment
		(start 316.868302 -297.632374)
		(end 316.868302 -300.362874)
		(width 0.18288)
		(layer "In2.Cu")
		(net "M_A_CPU0_SA_DQS_DP<1>")
	)
	(segment
		(start 314.278264 -303.991518)
		(end 313.906662 -303.991518)
		(width 0.18288)
		(layer "In2.Cu")
		(net "M_A_CPU0_SA_DQS_DP<1>")
	)
	(segment
		(start 316.868302 -300.362874)
		(end 315.917834 -302.65751)
		(width 0.18288)
		(layer "In2.Cu")
		(net "M_A_CPU0_SA_DQS_DP<1>")
	)
	(segment
		(start 311.665112 -302.94707)
		(end 311.018428 -302.94707)
		(width 0.18288)
		(layer "In2.Cu")
		(net "M_A_CPU0_SA_DQS_DP<1>")
	)
	(segment
		(start 333.044038 -271.365726)
		(end 332.783688 -271.626076)
		(width 0.18288)
		(layer "In2.Cu")
		(net "M_A_CPU0_SA_DQS_DP<1>")
	)
	(segment
		(start 336.164936 -270.570706)
		(end 336.131916 -270.603726)
		(width 0.088646)
		(layer "In2.Cu")
		(net "M_A_CPU0_SA_DQS_DP<1>")
	)
	(segment
		(start 335.682336 -270.603726)
		(end 335.538064 -270.687038)
		(width 0.088646)
		(layer "In2.Cu")
		(net "M_A_CPU0_SA_DQS_DP<1>")
	)
	(arc
		(start 334.598264 -270.687038)
		(mid 334.557334 -270.714071)
		(end 334.520286 -270.74622)
		(width 0.088646)
		(layer "In2.Cu")
		(net "M_A_CPU0_SA_DQS_DP<1>")
	)
	(arc
		(start 336.369406 -270.52905)
		(mid 336.270564 -270.56656)
		(end 336.164936 -270.570706)
		(width 0.088646)
		(layer "In2.Cu")
		(net "M_A_CPU0_SA_DQS_DP<1>")
	)
	(arc
		(start 334.97266 -270.687038)
		(mid 334.785462 -270.636895)
		(end 334.598264 -270.687038)
		(width 0.088646)
		(layer "In2.Cu")
		(net "M_A_CPU0_SA_DQS_DP<1>")
	)
	(arc
		(start 335.538064 -270.687038)
		(mid 335.255362 -270.762814)
		(end 334.97266 -270.687038)
		(width 0.088646)
		(layer "In2.Cu")
		(net "M_A_CPU0_SA_DQS_DP<1>")
	)
	(segment
		(start 308.077362 -312.655458)
		(end 308.338474 -312.91657)
		(width 0.20066)
		(layer "F.Cu")
		(net "M_A_CPU0_SA_DQS_DP<0>")
	)
	(segment
		(start 303.638458 -313.080654)
		(end 303.908968 -313.351164)
		(width 0.20066)
		(layer "F.Cu")
		(net "M_A_CPU0_SA_DQS_DP<0>")
	)
	(segment
		(start 320.390774 -307.877972)
		(end 324.637654 -304.39233)
		(width 0.20066)
		(layer "F.Cu")
		(net "M_A_CPU0_SA_DQS_DP<0>")
	)
	(segment
		(start 306.973986 -313.349132)
		(end 307.242464 -313.080654)
		(width 0.20066)
		(layer "F.Cu")
		(net "M_A_CPU0_SA_DQS_DP<0>")
	)
	(segment
		(start 307.492146 -313.080654)
		(end 307.917342 -312.655458)
		(width 0.20066)
		(layer "F.Cu")
		(net "M_A_CPU0_SA_DQS_DP<0>")
	)
	(segment
		(start 306.636928 -313.341766)
		(end 306.644294 -313.349132)
		(width 0.1016)
		(layer "F.Cu")
		(net "M_A_CPU0_SA_DQS_DP<0>")
	)
	(segment
		(start 331.314552 -297.312334)
		(end 331.53858 -296.185082)
		(width 0.1524)
		(layer "F.Cu")
		(net "M_A_CPU0_SA_DQS_DP<0>")
	)
	(segment
		(start 301.881286 -312.91657)
		(end 302.142398 -312.655458)
		(width 0.20066)
		(layer "F.Cu")
		(net "M_A_CPU0_SA_DQS_DP<0>")
	)
	(segment
		(start 308.338474 -312.91657)
		(end 308.887114 -312.91657)
		(width 0.20066)
		(layer "F.Cu")
		(net "M_A_CPU0_SA_DQS_DP<0>")
	)
	(segment
		(start 309.63108 -312.665364)
		(end 309.85714 -312.665364)
		(width 0.20066)
		(layer "F.Cu")
		(net "M_A_CPU0_SA_DQS_DP<0>")
	)
	(segment
		(start 309.85714 -312.665364)
		(end 310.883046 -313.090306)
		(width 0.20066)
		(layer "F.Cu")
		(net "M_A_CPU0_SA_DQS_DP<0>")
	)
	(segment
		(start 303.247552 -313.080654)
		(end 303.638458 -313.080654)
		(width 0.20066)
		(layer "F.Cu")
		(net "M_A_CPU0_SA_DQS_DP<0>")
	)
	(segment
		(start 302.611536 -312.655458)
		(end 303.247552 -313.080654)
		(width 0.20066)
		(layer "F.Cu")
		(net "M_A_CPU0_SA_DQS_DP<0>")
	)
	(segment
		(start 311.981596 -313.356244)
		(end 311.996328 -313.341512)
		(width 0.1016)
		(layer "F.Cu")
		(net "M_A_CPU0_SA_DQS_DP<0>")
	)
	(segment
		(start 310.883046 -313.090306)
		(end 311.194704 -313.090306)
		(width 0.20066)
		(layer "F.Cu")
		(net "M_A_CPU0_SA_DQS_DP<0>")
	)
	(segment
		(start 311.94248 -313.356244)
		(end 311.981596 -313.356244)
		(width 0.1016)
		(layer "F.Cu")
		(net "M_A_CPU0_SA_DQS_DP<0>")
	)
	(segment
		(start 331.53858 -282.419298)
		(end 332.063344 -279.796494)
		(width 0.1524)
		(layer "F.Cu")
		(net "M_A_CPU0_SA_DQS_DP<0>")
	)
	(segment
		(start 330.711302 -298.266358)
		(end 331.071982 -297.905678)
		(width 0.1524)
		(layer "F.Cu")
		(net "M_A_CPU0_SA_DQS_DP<0>")
	)
	(segment
		(start 314.082684 -313.341512)
		(end 314.088272 -313.3471)
		(width 0.1016)
		(layer "F.Cu")
		(net "M_A_CPU0_SA_DQS_DP<0>")
	)
	(segment
		(start 332.619858 -279.194768)
		(end 332.74127 -278.902922)
		(width 0.088646)
		(layer "F.Cu")
		(net "M_A_CPU0_SA_DQS_DP<0>")
	)
	(segment
		(start 309.379874 -312.91657)
		(end 309.63108 -312.665364)
		(width 0.20066)
		(layer "F.Cu")
		(net "M_A_CPU0_SA_DQS_DP<0>")
	)
	(segment
		(start 302.142398 -312.655458)
		(end 302.611536 -312.655458)
		(width 0.20066)
		(layer "F.Cu")
		(net "M_A_CPU0_SA_DQS_DP<0>")
	)
	(segment
		(start 332.74127 -278.632666)
		(end 332.817978 -278.446484)
		(width 0.088646)
		(layer "F.Cu")
		(net "M_A_CPU0_SA_DQS_DP<0>")
	)
	(segment
		(start 306.644294 -313.349132)
		(end 306.973986 -313.349132)
		(width 0.20066)
		(layer "F.Cu")
		(net "M_A_CPU0_SA_DQS_DP<0>")
	)
	(segment
		(start 308.887114 -312.91657)
		(end 309.379874 -312.91657)
		(width 0.20066)
		(layer "F.Cu")
		(net "M_A_CPU0_SA_DQS_DP<0>")
	)
	(segment
		(start 314.088272 -313.3471)
		(end 314.10148 -313.3471)
		(width 0.1016)
		(layer "F.Cu")
		(net "M_A_CPU0_SA_DQS_DP<0>")
	)
	(segment
		(start 330.684378 -298.345606)
		(end 330.711302 -298.318682)
		(width 0.1524)
		(layer "F.Cu")
		(net "M_A_CPU0_SA_DQS_DP<0>")
	)
	(segment
		(start 332.817978 -278.446484)
		(end 332.936342 -278.32812)
		(width 0.088646)
		(layer "F.Cu")
		(net "M_A_CPU0_SA_DQS_DP<0>")
	)
	(segment
		(start 332.338172 -279.521666)
		(end 332.338172 -279.476454)
		(width 0.088646)
		(layer "F.Cu")
		(net "M_A_CPU0_SA_DQS_DP<0>")
	)
	(segment
		(start 334.004666 -277.800562)
		(end 334.315562 -277.800562)
		(width 0.088646)
		(layer "F.Cu")
		(net "M_A_CPU0_SA_DQS_DP<0>")
	)
	(segment
		(start 332.338172 -279.476454)
		(end 332.619858 -279.194768)
		(width 0.088646)
		(layer "F.Cu")
		(net "M_A_CPU0_SA_DQS_DP<0>")
	)
	(segment
		(start 315.320426 -312.948066)
		(end 320.390774 -307.877972)
		(width 0.20066)
		(layer "F.Cu")
		(net "M_A_CPU0_SA_DQS_DP<0>")
	)
	(segment
		(start 304.319178 -313.351164)
		(end 304.328576 -313.341766)
		(width 0.1016)
		(layer "F.Cu")
		(net "M_A_CPU0_SA_DQS_DP<0>")
	)
	(segment
		(start 333.937102 -277.868126)
		(end 334.004666 -277.800562)
		(width 0.088646)
		(layer "F.Cu")
		(net "M_A_CPU0_SA_DQS_DP<0>")
	)
	(segment
		(start 314.10148 -313.3471)
		(end 314.529978 -313.3471)
		(width 0.20066)
		(layer "F.Cu")
		(net "M_A_CPU0_SA_DQS_DP<0>")
	)
	(segment
		(start 324.637654 -304.39233)
		(end 330.684378 -298.345606)
		(width 0.20066)
		(layer "F.Cu")
		(net "M_A_CPU0_SA_DQS_DP<0>")
	)
	(segment
		(start 331.071982 -297.905678)
		(end 331.314552 -297.312334)
		(width 0.1524)
		(layer "F.Cu")
		(net "M_A_CPU0_SA_DQS_DP<0>")
	)
	(segment
		(start 315.049154 -313.060334)
		(end 315.320426 -312.948066)
		(width 0.20066)
		(layer "F.Cu")
		(net "M_A_CPU0_SA_DQS_DP<0>")
	)
	(segment
		(start 307.242464 -313.080654)
		(end 307.492146 -313.080654)
		(width 0.20066)
		(layer "F.Cu")
		(net "M_A_CPU0_SA_DQS_DP<0>")
	)
	(segment
		(start 304.328576 -313.341766)
		(end 306.636928 -313.341766)
		(width 0.1016)
		(layer "F.Cu")
		(net "M_A_CPU0_SA_DQS_DP<0>")
	)
	(segment
		(start 311.996328 -313.341512)
		(end 314.082684 -313.341512)
		(width 0.1016)
		(layer "F.Cu")
		(net "M_A_CPU0_SA_DQS_DP<0>")
	)
	(segment
		(start 330.711302 -298.318682)
		(end 330.711302 -298.266358)
		(width 0.1524)
		(layer "F.Cu")
		(net "M_A_CPU0_SA_DQS_DP<0>")
	)
	(segment
		(start 311.39638 -313.291982)
		(end 311.55132 -313.356244)
		(width 0.20066)
		(layer "F.Cu")
		(net "M_A_CPU0_SA_DQS_DP<0>")
	)
	(segment
		(start 311.194704 -313.090306)
		(end 311.39638 -313.291982)
		(width 0.20066)
		(layer "F.Cu")
		(net "M_A_CPU0_SA_DQS_DP<0>")
	)
	(segment
		(start 332.322678 -279.53716)
		(end 332.338172 -279.521666)
		(width 0.088646)
		(layer "F.Cu")
		(net "M_A_CPU0_SA_DQS_DP<0>")
	)
	(segment
		(start 332.74127 -278.902922)
		(end 332.74127 -278.632666)
		(width 0.088646)
		(layer "F.Cu")
		(net "M_A_CPU0_SA_DQS_DP<0>")
	)
	(segment
		(start 303.908968 -313.351164)
		(end 304.319178 -313.351164)
		(width 0.20066)
		(layer "F.Cu")
		(net "M_A_CPU0_SA_DQS_DP<0>")
	)
	(segment
		(start 314.529978 -313.3471)
		(end 314.816744 -313.060334)
		(width 0.20066)
		(layer "F.Cu")
		(net "M_A_CPU0_SA_DQS_DP<0>")
	)
	(segment
		(start 332.063344 -279.796494)
		(end 332.322678 -279.53716)
		(width 0.1524)
		(layer "F.Cu")
		(net "M_A_CPU0_SA_DQS_DP<0>")
	)
	(segment
		(start 301.343314 -312.91657)
		(end 301.881286 -312.91657)
		(width 0.20066)
		(layer "F.Cu")
		(net "M_A_CPU0_SA_DQS_DP<0>")
	)
	(segment
		(start 307.917342 -312.655458)
		(end 308.077362 -312.655458)
		(width 0.20066)
		(layer "F.Cu")
		(net "M_A_CPU0_SA_DQS_DP<0>")
	)
	(segment
		(start 311.55132 -313.356244)
		(end 311.94248 -313.356244)
		(width 0.20066)
		(layer "F.Cu")
		(net "M_A_CPU0_SA_DQS_DP<0>")
	)
	(segment
		(start 331.53858 -296.185082)
		(end 331.53858 -282.419298)
		(width 0.1524)
		(layer "F.Cu")
		(net "M_A_CPU0_SA_DQS_DP<0>")
	)
	(segment
		(start 332.936342 -278.32812)
		(end 333.49819 -278.32812)
		(width 0.088646)
		(layer "F.Cu")
		(net "M_A_CPU0_SA_DQS_DP<0>")
	)
	(segment
		(start 314.816744 -313.060334)
		(end 315.049154 -313.060334)
		(width 0.20066)
		(layer "F.Cu")
		(net "M_A_CPU0_SA_DQS_DP<0>")
	)
	(arc
		(start 333.49819 -278.32812)
		(mid 333.597963 -278.313449)
		(end 333.689198 -278.270462)
		(width 0.088646)
		(layer "F.Cu")
		(net "M_A_CPU0_SA_DQS_DP<0>")
	)
	(arc
		(start 333.934054 -277.88997)
		(mid 333.935682 -277.879063)
		(end 333.937102 -277.868126)
		(width 0.088646)
		(layer "F.Cu")
		(net "M_A_CPU0_SA_DQS_DP<0>")
	)
	(arc
		(start 333.689198 -278.270462)
		(mid 333.851383 -278.105793)
		(end 333.934054 -277.88997)
		(width 0.088646)
		(layer "F.Cu")
		(net "M_A_CPU0_SA_DQS_DP<0>")
	)
	(segment
		(start 331.02677 -262.260334)
		(end 331.004672 -262.260334)
		(width 0.088646)
		(layer "F.Cu")
		(net "M_A_CPU0_SA_DQS_DN<9>")
	)
	(segment
		(start 310.346598 -274.241768)
		(end 310.48071 -274.241768)
		(width 0.20066)
		(layer "F.Cu")
		(net "M_A_CPU0_SA_DQS_DN<9>")
	)
	(segment
		(start 306.176172 -274.405598)
		(end 306.53863 -274.405598)
		(width 0.20066)
		(layer "F.Cu")
		(net "M_A_CPU0_SA_DQS_DN<9>")
	)
	(segment
		(start 311.777888 -274.405598)
		(end 312.235596 -274.405598)
		(width 0.20066)
		(layer "F.Cu")
		(net "M_A_CPU0_SA_DQS_DN<9>")
	)
	(segment
		(start 331.058774 -262.22833)
		(end 331.02677 -262.260334)
		(width 0.088646)
		(layer "F.Cu")
		(net "M_A_CPU0_SA_DQS_DN<9>")
	)
	(segment
		(start 306.53863 -274.405598)
		(end 306.961032 -273.983196)
		(width 0.20066)
		(layer "F.Cu")
		(net "M_A_CPU0_SA_DQS_DN<9>")
	)
	(segment
		(start 307.120036 -273.983196)
		(end 307.378608 -274.241768)
		(width 0.20066)
		(layer "F.Cu")
		(net "M_A_CPU0_SA_DQS_DN<9>")
	)
	(segment
		(start 322.93179 -268.289532)
		(end 322.904866 -268.316456)
		(width 0.1524)
		(layer "F.Cu")
		(net "M_A_CPU0_SA_DQS_DN<9>")
	)
	(segment
		(start 334.032352 -262.010906)
		(end 334.03159 -262.010652)
		(width 0.088646)
		(layer "F.Cu")
		(net "M_A_CPU0_SA_DQS_DN<9>")
	)
	(segment
		(start 310.741822 -273.980656)
		(end 311.141872 -273.980656)
		(width 0.20066)
		(layer "F.Cu")
		(net "M_A_CPU0_SA_DQS_DN<9>")
	)
	(segment
		(start 334.409034 -262.304022)
		(end 334.337406 -262.163306)
		(width 0.088646)
		(layer "F.Cu")
		(net "M_A_CPU0_SA_DQS_DN<9>")
	)
	(segment
		(start 335.354168 -262.437372)
		(end 334.972914 -262.660892)
		(width 0.088646)
		(layer "F.Cu")
		(net "M_A_CPU0_SA_DQS_DN<9>")
	)
	(segment
		(start 332.691232 -261.96163)
		(end 332.424532 -262.22833)
		(width 0.088646)
		(layer "F.Cu")
		(net "M_A_CPU0_SA_DQS_DN<9>")
	)
	(segment
		(start 332.905862 -261.96163)
		(end 332.691232 -261.96163)
		(width 0.088646)
		(layer "F.Cu")
		(net "M_A_CPU0_SA_DQS_DN<9>")
	)
	(segment
		(start 333.093314 -262.012176)
		(end 333.09306 -262.011922)
		(width 0.088646)
		(layer "F.Cu")
		(net "M_A_CPU0_SA_DQS_DN<9>")
	)
	(segment
		(start 334.03159 -262.010652)
		(end 334.029812 -262.009636)
		(width 0.088646)
		(layer "F.Cu")
		(net "M_A_CPU0_SA_DQS_DN<9>")
	)
	(segment
		(start 332.906116 -261.961884)
		(end 332.905862 -261.96163)
		(width 0.088646)
		(layer "F.Cu")
		(net "M_A_CPU0_SA_DQS_DN<9>")
	)
	(segment
		(start 333.103728 -262.018272)
		(end 333.093314 -262.012176)
		(width 0.088646)
		(layer "F.Cu")
		(net "M_A_CPU0_SA_DQS_DN<9>")
	)
	(segment
		(start 307.431186 -274.241768)
		(end 310.346598 -274.241768)
		(width 0.1016)
		(layer "F.Cu")
		(net "M_A_CPU0_SA_DQS_DN<9>")
	)
	(segment
		(start 333.658464 -262.011922)
		(end 333.658464 -262.012176)
		(width 0.088646)
		(layer "F.Cu")
		(net "M_A_CPU0_SA_DQS_DN<9>")
	)
	(segment
		(start 313.005216 -274.648676)
		(end 312.987182 -274.66671)
		(width 0.20066)
		(layer "F.Cu")
		(net "M_A_CPU0_SA_DQS_DN<9>")
	)
	(segment
		(start 322.93179 -268.237208)
		(end 322.93179 -268.289532)
		(width 0.1524)
		(layer "F.Cu")
		(net "M_A_CPU0_SA_DQS_DN<9>")
	)
	(segment
		(start 322.904866 -268.316456)
		(end 317.481966 -273.739356)
		(width 0.20066)
		(layer "F.Cu")
		(net "M_A_CPU0_SA_DQS_DN<9>")
	)
	(segment
		(start 334.41005 -262.318246)
		(end 334.410304 -262.318246)
		(width 0.088646)
		(layer "F.Cu")
		(net "M_A_CPU0_SA_DQS_DN<9>")
	)
	(segment
		(start 316.255146 -274.648676)
		(end 313.005216 -274.648676)
		(width 0.20066)
		(layer "F.Cu")
		(net "M_A_CPU0_SA_DQS_DN<9>")
	)
	(segment
		(start 324.630542 -267.805154)
		(end 323.363844 -267.805154)
		(width 0.1524)
		(layer "F.Cu")
		(net "M_A_CPU0_SA_DQS_DN<9>")
	)
	(segment
		(start 317.481966 -273.739356)
		(end 316.255146 -274.648676)
		(width 0.20066)
		(layer "F.Cu")
		(net "M_A_CPU0_SA_DQS_DN<9>")
	)
	(segment
		(start 310.48071 -274.241768)
		(end 310.741822 -273.980656)
		(width 0.20066)
		(layer "F.Cu")
		(net "M_A_CPU0_SA_DQS_DN<9>")
	)
	(segment
		(start 330.175362 -262.260334)
		(end 324.630542 -267.805154)
		(width 0.1524)
		(layer "F.Cu")
		(net "M_A_CPU0_SA_DQS_DN<9>")
	)
	(segment
		(start 305.91506 -274.66671)
		(end 306.176172 -274.405598)
		(width 0.20066)
		(layer "F.Cu")
		(net "M_A_CPU0_SA_DQS_DN<9>")
	)
	(segment
		(start 311.141872 -273.980656)
		(end 311.777888 -274.405598)
		(width 0.20066)
		(layer "F.Cu")
		(net "M_A_CPU0_SA_DQS_DN<9>")
	)
	(segment
		(start 334.337406 -262.163306)
		(end 334.032352 -262.010906)
		(width 0.088646)
		(layer "F.Cu")
		(net "M_A_CPU0_SA_DQS_DN<9>")
	)
	(segment
		(start 331.004672 -262.260334)
		(end 330.175362 -262.260334)
		(width 0.1524)
		(layer "F.Cu")
		(net "M_A_CPU0_SA_DQS_DN<9>")
	)
	(segment
		(start 334.415892 -262.396986)
		(end 334.41005 -262.318246)
		(width 0.088646)
		(layer "F.Cu")
		(net "M_A_CPU0_SA_DQS_DN<9>")
	)
	(segment
		(start 312.235596 -274.405598)
		(end 312.496708 -274.66671)
		(width 0.20066)
		(layer "F.Cu")
		(net "M_A_CPU0_SA_DQS_DN<9>")
	)
	(segment
		(start 334.410304 -262.318246)
		(end 334.409034 -262.304022)
		(width 0.088646)
		(layer "F.Cu")
		(net "M_A_CPU0_SA_DQS_DN<9>")
	)
	(segment
		(start 306.961032 -273.983196)
		(end 307.120036 -273.983196)
		(width 0.20066)
		(layer "F.Cu")
		(net "M_A_CPU0_SA_DQS_DN<9>")
	)
	(segment
		(start 323.363844 -267.805154)
		(end 322.93179 -268.237208)
		(width 0.1524)
		(layer "F.Cu")
		(net "M_A_CPU0_SA_DQS_DN<9>")
	)
	(segment
		(start 312.496708 -274.66671)
		(end 312.987182 -274.66671)
		(width 0.20066)
		(layer "F.Cu")
		(net "M_A_CPU0_SA_DQS_DN<9>")
	)
	(segment
		(start 307.378608 -274.241768)
		(end 307.431186 -274.241768)
		(width 0.20066)
		(layer "F.Cu")
		(net "M_A_CPU0_SA_DQS_DN<9>")
	)
	(segment
		(start 332.424532 -262.22833)
		(end 331.058774 -262.22833)
		(width 0.088646)
		(layer "F.Cu")
		(net "M_A_CPU0_SA_DQS_DN<9>")
	)
	(segment
		(start 334.029812 -262.009636)
		(end 334.02651 -262.007858)
		(width 0.088646)
		(layer "F.Cu")
		(net "M_A_CPU0_SA_DQS_DN<9>")
	)
	(segment
		(start 305.443382 -274.66671)
		(end 305.91506 -274.66671)
		(width 0.20066)
		(layer "F.Cu")
		(net "M_A_CPU0_SA_DQS_DN<9>")
	)
	(arc
		(start 334.598518 -262.660892)
		(mid 334.477551 -262.54946)
		(end 334.415892 -262.396986)
		(width 0.088646)
		(layer "F.Cu")
		(net "M_A_CPU0_SA_DQS_DN<9>")
	)
	(arc
		(start 334.972914 -262.660892)
		(mid 334.785716 -262.711035)
		(end 334.598518 -262.660892)
		(width 0.088646)
		(layer "F.Cu")
		(net "M_A_CPU0_SA_DQS_DN<9>")
	)
	(arc
		(start 333.09306 -262.011922)
		(mid 333.00288 -261.974601)
		(end 332.906116 -261.961884)
		(width 0.088646)
		(layer "F.Cu")
		(net "M_A_CPU0_SA_DQS_DN<9>")
	)
	(arc
		(start 335.725262 -262.336534)
		(mid 335.532986 -262.362191)
		(end 335.354168 -262.437372)
		(width 0.088646)
		(layer "F.Cu")
		(net "M_A_CPU0_SA_DQS_DN<9>")
	)
	(arc
		(start 334.02651 -262.007858)
		(mid 333.841964 -261.961657)
		(end 333.658464 -262.011922)
		(width 0.088646)
		(layer "F.Cu")
		(net "M_A_CPU0_SA_DQS_DN<9>")
	)
	(arc
		(start 333.658464 -262.012176)
		(mid 333.381905 -262.087919)
		(end 333.103728 -262.018272)
		(width 0.088646)
		(layer "F.Cu")
		(net "M_A_CPU0_SA_DQS_DN<9>")
	)
	(segment
		(start 312.235596 -283.755592)
		(end 312.496708 -284.016704)
		(width 0.20066)
		(layer "F.Cu")
		(net "M_A_CPU0_SA_DQS_DN<8>")
	)
	(segment
		(start 322.460366 -281.0764)
		(end 322.433442 -281.103324)
		(width 0.1524)
		(layer "F.Cu")
		(net "M_A_CPU0_SA_DQS_DN<8>")
	)
	(segment
		(start 306.551584 -283.72943)
		(end 306.947824 -283.33319)
		(width 0.20066)
		(layer "F.Cu")
		(net "M_A_CPU0_SA_DQS_DN<8>")
	)
	(segment
		(start 334.029812 -266.89304)
		(end 334.02651 -266.891262)
		(width 0.088646)
		(layer "F.Cu")
		(net "M_A_CPU0_SA_DQS_DN<8>")
	)
	(segment
		(start 335.725262 -267.219938)
		(end 335.158588 -267.416026)
		(width 0.088646)
		(layer "F.Cu")
		(net "M_A_CPU0_SA_DQS_DN<8>")
	)
	(segment
		(start 310.088026 -283.601414)
		(end 310.385206 -283.601414)
		(width 0.20066)
		(layer "F.Cu")
		(net "M_A_CPU0_SA_DQS_DN<8>")
	)
	(segment
		(start 307.76291 -283.601414)
		(end 307.764434 -283.601414)
		(width 0.1016)
		(layer "F.Cu")
		(net "M_A_CPU0_SA_DQS_DN<8>")
	)
	(segment
		(start 311.777888 -283.755592)
		(end 312.235596 -283.755592)
		(width 0.20066)
		(layer "F.Cu")
		(net "M_A_CPU0_SA_DQS_DN<8>")
	)
	(segment
		(start 334.506062 -267.483844)
		(end 334.495648 -267.483844)
		(width 0.088646)
		(layer "F.Cu")
		(net "M_A_CPU0_SA_DQS_DN<8>")
	)
	(segment
		(start 307.28158 -283.33319)
		(end 307.549804 -283.601414)
		(width 0.20066)
		(layer "F.Cu")
		(net "M_A_CPU0_SA_DQS_DN<8>")
	)
	(segment
		(start 331.345286 -268.138148)
		(end 331.345286 -268.183868)
		(width 0.088646)
		(layer "F.Cu")
		(net "M_A_CPU0_SA_DQS_DN<8>")
	)
	(segment
		(start 310.385206 -283.601414)
		(end 310.65597 -283.33065)
		(width 0.20066)
		(layer "F.Cu")
		(net "M_A_CPU0_SA_DQS_DN<8>")
	)
	(segment
		(start 325.272908 -274.256246)
		(end 323.941948 -276.713442)
		(width 0.1524)
		(layer "F.Cu")
		(net "M_A_CPU0_SA_DQS_DN<8>")
	)
	(segment
		(start 318.824102 -283.960062)
		(end 318.539114 -284.016704)
		(width 0.20066)
		(layer "F.Cu")
		(net "M_A_CPU0_SA_DQS_DN<8>")
	)
	(segment
		(start 310.067706 -283.591762)
		(end 310.077358 -283.601414)
		(width 0.1016)
		(layer "F.Cu")
		(net "M_A_CPU0_SA_DQS_DN<8>")
	)
	(segment
		(start 323.941948 -276.713442)
		(end 323.25818 -279.968198)
		(width 0.1524)
		(layer "F.Cu")
		(net "M_A_CPU0_SA_DQS_DN<8>")
	)
	(segment
		(start 333.0702 -266.878816)
		(end 332.604618 -266.878816)
		(width 0.088646)
		(layer "F.Cu")
		(net "M_A_CPU0_SA_DQS_DN<8>")
	)
	(segment
		(start 334.214216 -267.140436)
		(end 334.108298 -266.93241)
		(width 0.088646)
		(layer "F.Cu")
		(net "M_A_CPU0_SA_DQS_DN<8>")
	)
	(segment
		(start 306.947824 -283.33319)
		(end 307.28158 -283.33319)
		(width 0.20066)
		(layer "F.Cu")
		(net "M_A_CPU0_SA_DQS_DN<8>")
	)
	(segment
		(start 310.65597 -283.33065)
		(end 311.141872 -283.33065)
		(width 0.20066)
		(layer "F.Cu")
		(net "M_A_CPU0_SA_DQS_DN<8>")
	)
	(segment
		(start 307.774086 -283.591762)
		(end 310.067706 -283.591762)
		(width 0.1016)
		(layer "F.Cu")
		(net "M_A_CPU0_SA_DQS_DN<8>")
	)
	(segment
		(start 332.604618 -266.878816)
		(end 331.345286 -268.138148)
		(width 0.088646)
		(layer "F.Cu")
		(net "M_A_CPU0_SA_DQS_DN<8>")
	)
	(segment
		(start 333.153258 -266.961874)
		(end 333.0702 -266.878816)
		(width 0.088646)
		(layer "F.Cu")
		(net "M_A_CPU0_SA_DQS_DN<8>")
	)
	(segment
		(start 322.433442 -281.103324)
		(end 320.10858 -283.428186)
		(width 0.20066)
		(layer "F.Cu")
		(net "M_A_CPU0_SA_DQS_DN<8>")
	)
	(segment
		(start 331.329792 -268.199362)
		(end 325.272908 -274.256246)
		(width 0.1524)
		(layer "F.Cu")
		(net "M_A_CPU0_SA_DQS_DN<8>")
	)
	(segment
		(start 323.25818 -279.968198)
		(end 322.955158 -280.529284)
		(width 0.1524)
		(layer "F.Cu")
		(net "M_A_CPU0_SA_DQS_DN<8>")
	)
	(segment
		(start 331.345286 -268.183868)
		(end 331.329792 -268.199362)
		(width 0.088646)
		(layer "F.Cu")
		(net "M_A_CPU0_SA_DQS_DN<8>")
	)
	(segment
		(start 335.158588 -267.416026)
		(end 334.972914 -267.544296)
		(width 0.088646)
		(layer "F.Cu")
		(net "M_A_CPU0_SA_DQS_DN<8>")
	)
	(segment
		(start 333.591916 -266.961874)
		(end 333.153258 -266.961874)
		(width 0.088646)
		(layer "F.Cu")
		(net "M_A_CPU0_SA_DQS_DN<8>")
	)
	(segment
		(start 312.496708 -284.016704)
		(end 312.987182 -284.016704)
		(width 0.20066)
		(layer "F.Cu")
		(net "M_A_CPU0_SA_DQS_DN<8>")
	)
	(segment
		(start 307.549804 -283.601414)
		(end 307.76291 -283.601414)
		(width 0.20066)
		(layer "F.Cu")
		(net "M_A_CPU0_SA_DQS_DN<8>")
	)
	(segment
		(start 322.460366 -281.023822)
		(end 322.460366 -281.0764)
		(width 0.1524)
		(layer "F.Cu")
		(net "M_A_CPU0_SA_DQS_DN<8>")
	)
	(segment
		(start 318.539114 -284.016704)
		(end 312.987182 -284.016704)
		(width 0.20066)
		(layer "F.Cu")
		(net "M_A_CPU0_SA_DQS_DN<8>")
	)
	(segment
		(start 305.91506 -284.016704)
		(end 306.202334 -283.72943)
		(width 0.20066)
		(layer "F.Cu")
		(net "M_A_CPU0_SA_DQS_DN<8>")
	)
	(segment
		(start 311.141872 -283.33065)
		(end 311.777888 -283.755592)
		(width 0.20066)
		(layer "F.Cu")
		(net "M_A_CPU0_SA_DQS_DN<8>")
	)
	(segment
		(start 306.202334 -283.72943)
		(end 306.551584 -283.72943)
		(width 0.20066)
		(layer "F.Cu")
		(net "M_A_CPU0_SA_DQS_DN<8>")
	)
	(segment
		(start 310.077358 -283.601414)
		(end 310.088026 -283.601414)
		(width 0.1016)
		(layer "F.Cu")
		(net "M_A_CPU0_SA_DQS_DN<8>")
	)
	(segment
		(start 334.03159 -266.894056)
		(end 334.029812 -266.89304)
		(width 0.088646)
		(layer "F.Cu")
		(net "M_A_CPU0_SA_DQS_DN<8>")
	)
	(segment
		(start 307.764434 -283.601414)
		(end 307.774086 -283.591762)
		(width 0.1016)
		(layer "F.Cu")
		(net "M_A_CPU0_SA_DQS_DN<8>")
	)
	(segment
		(start 305.443382 -284.016704)
		(end 305.91506 -284.016704)
		(width 0.20066)
		(layer "F.Cu")
		(net "M_A_CPU0_SA_DQS_DN<8>")
	)
	(segment
		(start 322.955158 -280.529284)
		(end 322.460366 -281.023822)
		(width 0.1524)
		(layer "F.Cu")
		(net "M_A_CPU0_SA_DQS_DN<8>")
	)
	(segment
		(start 334.495648 -267.483844)
		(end 334.33639 -267.324586)
		(width 0.088646)
		(layer "F.Cu")
		(net "M_A_CPU0_SA_DQS_DN<8>")
	)
	(segment
		(start 334.108298 -266.93241)
		(end 334.032352 -266.89431)
		(width 0.088646)
		(layer "F.Cu")
		(net "M_A_CPU0_SA_DQS_DN<8>")
	)
	(segment
		(start 320.10858 -283.428186)
		(end 318.824102 -283.960062)
		(width 0.20066)
		(layer "F.Cu")
		(net "M_A_CPU0_SA_DQS_DN<8>")
	)
	(segment
		(start 334.33639 -267.324586)
		(end 334.33639 -267.32484)
		(width 0.088646)
		(layer "F.Cu")
		(net "M_A_CPU0_SA_DQS_DN<8>")
	)
	(segment
		(start 333.658464 -266.895326)
		(end 333.591916 -266.961874)
		(width 0.088646)
		(layer "F.Cu")
		(net "M_A_CPU0_SA_DQS_DN<8>")
	)
	(segment
		(start 334.032352 -266.89431)
		(end 334.03159 -266.894056)
		(width 0.088646)
		(layer "F.Cu")
		(net "M_A_CPU0_SA_DQS_DN<8>")
	)
	(arc
		(start 333.719424 -266.867132)
		(mid 333.688309 -266.879857)
		(end 333.658464 -266.895326)
		(width 0.088646)
		(layer "F.Cu")
		(net "M_A_CPU0_SA_DQS_DN<8>")
	)
	(arc
		(start 334.972914 -267.544296)
		(mid 334.785716 -267.594439)
		(end 334.598518 -267.544296)
		(width 0.088646)
		(layer "F.Cu")
		(net "M_A_CPU0_SA_DQS_DN<8>")
	)
	(arc
		(start 334.598518 -267.544296)
		(mid 334.551439 -267.515372)
		(end 334.506062 -267.483844)
		(width 0.088646)
		(layer "F.Cu")
		(net "M_A_CPU0_SA_DQS_DN<8>")
	)
	(arc
		(start 334.33639 -267.32484)
		(mid 334.276624 -267.245737)
		(end 334.225138 -267.16101)
		(width 0.088646)
		(layer "F.Cu")
		(net "M_A_CPU0_SA_DQS_DN<8>")
	)
	(arc
		(start 334.225138 -267.16101)
		(mid 334.219573 -267.150778)
		(end 334.214216 -267.140436)
		(width 0.088646)
		(layer "F.Cu")
		(net "M_A_CPU0_SA_DQS_DN<8>")
	)
	(arc
		(start 334.02651 -266.891262)
		(mid 333.875559 -266.846191)
		(end 333.719424 -266.867132)
		(width 0.088646)
		(layer "F.Cu")
		(net "M_A_CPU0_SA_DQS_DN<8>")
	)
	(segment
		(start 333.05623 -272.062194)
		(end 332.999842 -272.118328)
		(width 0.088646)
		(layer "F.Cu")
		(net "M_A_CPU0_SA_DQS_DN<7>")
	)
	(segment
		(start 311.42813 -293.105586)
		(end 312.235596 -293.105586)
		(width 0.20066)
		(layer "F.Cu")
		(net "M_A_CPU0_SA_DQS_DN<7>")
	)
	(segment
		(start 327.01738 -289.800538)
		(end 326.870822 -290.153852)
		(width 0.1524)
		(layer "F.Cu")
		(net "M_A_CPU0_SA_DQS_DN<7>")
	)
	(segment
		(start 334.41005 -272.085054)
		(end 334.410304 -272.085054)
		(width 0.088646)
		(layer "F.Cu")
		(net "M_A_CPU0_SA_DQS_DN<7>")
	)
	(segment
		(start 326.614536 -290.46297)
		(end 326.587612 -290.489894)
		(width 0.1524)
		(layer "F.Cu")
		(net "M_A_CPU0_SA_DQS_DN<7>")
	)
	(segment
		(start 310.491378 -292.680644)
		(end 310.792114 -292.680644)
		(width 0.20066)
		(layer "F.Cu")
		(net "M_A_CPU0_SA_DQS_DN<7>")
	)
	(segment
		(start 334.032352 -271.777714)
		(end 334.03159 -271.77746)
		(width 0.088646)
		(layer "F.Cu")
		(net "M_A_CPU0_SA_DQS_DN<7>")
	)
	(segment
		(start 333.260446 -271.977358)
		(end 333.05623 -272.062194)
		(width 0.088646)
		(layer "F.Cu")
		(net "M_A_CPU0_SA_DQS_DN<7>")
	)
	(segment
		(start 306.961032 -292.683184)
		(end 307.120036 -292.683184)
		(width 0.20066)
		(layer "F.Cu")
		(net "M_A_CPU0_SA_DQS_DN<7>")
	)
	(segment
		(start 313.016392 -293.337488)
		(end 312.987182 -293.366698)
		(width 0.20066)
		(layer "F.Cu")
		(net "M_A_CPU0_SA_DQS_DN<7>")
	)
	(segment
		(start 333.580486 -271.838166)
		(end 333.441294 -271.977358)
		(width 0.088646)
		(layer "F.Cu")
		(net "M_A_CPU0_SA_DQS_DN<7>")
	)
	(segment
		(start 326.587612 -290.489894)
		(end 324.38213 -292.695376)
		(width 0.20066)
		(layer "F.Cu")
		(net "M_A_CPU0_SA_DQS_DN<7>")
	)
	(segment
		(start 312.496708 -293.366698)
		(end 312.987182 -293.366698)
		(width 0.20066)
		(layer "F.Cu")
		(net "M_A_CPU0_SA_DQS_DN<7>")
	)
	(segment
		(start 305.443382 -293.366698)
		(end 305.91506 -293.366698)
		(width 0.20066)
		(layer "F.Cu")
		(net "M_A_CPU0_SA_DQS_DN<7>")
	)
	(segment
		(start 310.792114 -292.680644)
		(end 311.42813 -293.105586)
		(width 0.20066)
		(layer "F.Cu")
		(net "M_A_CPU0_SA_DQS_DN<7>")
	)
	(segment
		(start 332.999842 -272.118328)
		(end 333.000096 -272.118328)
		(width 0.088646)
		(layer "F.Cu")
		(net "M_A_CPU0_SA_DQS_DN<7>")
	)
	(segment
		(start 310.088026 -292.951408)
		(end 310.220614 -292.951408)
		(width 0.20066)
		(layer "F.Cu")
		(net "M_A_CPU0_SA_DQS_DN<7>")
	)
	(segment
		(start 310.220614 -292.951408)
		(end 310.491378 -292.680644)
		(width 0.20066)
		(layer "F.Cu")
		(net "M_A_CPU0_SA_DQS_DN<7>")
	)
	(segment
		(start 333.000096 -272.118328)
		(end 331.670914 -273.44751)
		(width 0.088646)
		(layer "F.Cu")
		(net "M_A_CPU0_SA_DQS_DN<7>")
	)
	(segment
		(start 307.76291 -292.951408)
		(end 307.764434 -292.951408)
		(width 0.1016)
		(layer "F.Cu")
		(net "M_A_CPU0_SA_DQS_DN<7>")
	)
	(segment
		(start 334.03159 -271.77746)
		(end 334.029812 -271.776444)
		(width 0.088646)
		(layer "F.Cu")
		(net "M_A_CPU0_SA_DQS_DN<7>")
	)
	(segment
		(start 305.91506 -293.366698)
		(end 306.176172 -293.105586)
		(width 0.20066)
		(layer "F.Cu")
		(net "M_A_CPU0_SA_DQS_DN<7>")
	)
	(segment
		(start 307.38826 -292.951408)
		(end 307.76291 -292.951408)
		(width 0.20066)
		(layer "F.Cu")
		(net "M_A_CPU0_SA_DQS_DN<7>")
	)
	(segment
		(start 331.500226 -273.617436)
		(end 331.500226 -273.663156)
		(width 0.088646)
		(layer "F.Cu")
		(net "M_A_CPU0_SA_DQS_DN<7>")
	)
	(segment
		(start 328.432922 -276.73046)
		(end 327.725532 -278.051768)
		(width 0.1524)
		(layer "F.Cu")
		(net "M_A_CPU0_SA_DQS_DN<7>")
	)
	(segment
		(start 312.235596 -293.105586)
		(end 312.496708 -293.366698)
		(width 0.20066)
		(layer "F.Cu")
		(net "M_A_CPU0_SA_DQS_DN<7>")
	)
	(segment
		(start 335.354168 -272.20418)
		(end 334.972914 -272.4277)
		(width 0.088646)
		(layer "F.Cu")
		(net "M_A_CPU0_SA_DQS_DN<7>")
	)
	(segment
		(start 310.067706 -292.941756)
		(end 310.077358 -292.951408)
		(width 0.1016)
		(layer "F.Cu")
		(net "M_A_CPU0_SA_DQS_DN<7>")
	)
	(segment
		(start 327.01738 -281.592782)
		(end 327.01738 -289.800538)
		(width 0.1524)
		(layer "F.Cu")
		(net "M_A_CPU0_SA_DQS_DN<7>")
	)
	(segment
		(start 334.029812 -271.776444)
		(end 334.02651 -271.774666)
		(width 0.088646)
		(layer "F.Cu")
		(net "M_A_CPU0_SA_DQS_DN<7>")
	)
	(segment
		(start 307.774086 -292.941756)
		(end 310.067706 -292.941756)
		(width 0.1016)
		(layer "F.Cu")
		(net "M_A_CPU0_SA_DQS_DN<7>")
	)
	(segment
		(start 333.580486 -271.83842)
		(end 333.580486 -271.838166)
		(width 0.088646)
		(layer "F.Cu")
		(net "M_A_CPU0_SA_DQS_DN<7>")
	)
	(segment
		(start 334.415892 -272.163794)
		(end 334.41005 -272.085054)
		(width 0.088646)
		(layer "F.Cu")
		(net "M_A_CPU0_SA_DQS_DN<7>")
	)
	(segment
		(start 331.670152 -273.44751)
		(end 331.500226 -273.617436)
		(width 0.088646)
		(layer "F.Cu")
		(net "M_A_CPU0_SA_DQS_DN<7>")
	)
	(segment
		(start 326.614536 -290.410138)
		(end 326.614536 -290.46297)
		(width 0.1524)
		(layer "F.Cu")
		(net "M_A_CPU0_SA_DQS_DN<7>")
	)
	(segment
		(start 327.725532 -278.051768)
		(end 327.01738 -281.592782)
		(width 0.1524)
		(layer "F.Cu")
		(net "M_A_CPU0_SA_DQS_DN<7>")
	)
	(segment
		(start 310.077358 -292.951408)
		(end 310.088026 -292.951408)
		(width 0.1016)
		(layer "F.Cu")
		(net "M_A_CPU0_SA_DQS_DN<7>")
	)
	(segment
		(start 322.831714 -293.337488)
		(end 313.016392 -293.337488)
		(width 0.20066)
		(layer "F.Cu")
		(net "M_A_CPU0_SA_DQS_DN<7>")
	)
	(segment
		(start 306.53863 -293.105586)
		(end 306.961032 -292.683184)
		(width 0.20066)
		(layer "F.Cu")
		(net "M_A_CPU0_SA_DQS_DN<7>")
	)
	(segment
		(start 334.337406 -271.930114)
		(end 334.032352 -271.777714)
		(width 0.088646)
		(layer "F.Cu")
		(net "M_A_CPU0_SA_DQS_DN<7>")
	)
	(segment
		(start 333.441294 -271.977358)
		(end 333.260446 -271.977358)
		(width 0.088646)
		(layer "F.Cu")
		(net "M_A_CPU0_SA_DQS_DN<7>")
	)
	(segment
		(start 306.176172 -293.105586)
		(end 306.53863 -293.105586)
		(width 0.20066)
		(layer "F.Cu")
		(net "M_A_CPU0_SA_DQS_DN<7>")
	)
	(segment
		(start 326.870822 -290.153852)
		(end 326.614536 -290.410138)
		(width 0.1524)
		(layer "F.Cu")
		(net "M_A_CPU0_SA_DQS_DN<7>")
	)
	(segment
		(start 334.409034 -272.07083)
		(end 334.337406 -271.930114)
		(width 0.088646)
		(layer "F.Cu")
		(net "M_A_CPU0_SA_DQS_DN<7>")
	)
	(segment
		(start 334.410304 -272.085054)
		(end 334.409034 -272.07083)
		(width 0.088646)
		(layer "F.Cu")
		(net "M_A_CPU0_SA_DQS_DN<7>")
	)
	(segment
		(start 307.764434 -292.951408)
		(end 307.774086 -292.941756)
		(width 0.1016)
		(layer "F.Cu")
		(net "M_A_CPU0_SA_DQS_DN<7>")
	)
	(segment
		(start 307.120036 -292.683184)
		(end 307.38826 -292.951408)
		(width 0.20066)
		(layer "F.Cu")
		(net "M_A_CPU0_SA_DQS_DN<7>")
	)
	(segment
		(start 331.484732 -273.67865)
		(end 328.432922 -276.73046)
		(width 0.1524)
		(layer "F.Cu")
		(net "M_A_CPU0_SA_DQS_DN<7>")
	)
	(segment
		(start 331.500226 -273.663156)
		(end 331.484732 -273.67865)
		(width 0.088646)
		(layer "F.Cu")
		(net "M_A_CPU0_SA_DQS_DN<7>")
	)
	(segment
		(start 324.38213 -292.695376)
		(end 322.831714 -293.337488)
		(width 0.20066)
		(layer "F.Cu")
		(net "M_A_CPU0_SA_DQS_DN<7>")
	)
	(segment
		(start 331.670914 -273.44751)
		(end 331.670152 -273.44751)
		(width 0.088646)
		(layer "F.Cu")
		(net "M_A_CPU0_SA_DQS_DN<7>")
	)
	(arc
		(start 334.02651 -271.774666)
		(mid 333.84171 -271.728343)
		(end 333.657956 -271.77873)
		(width 0.088646)
		(layer "F.Cu")
		(net "M_A_CPU0_SA_DQS_DN<7>")
	)
	(arc
		(start 333.657956 -271.77873)
		(mid 333.617269 -271.806041)
		(end 333.580486 -271.83842)
		(width 0.088646)
		(layer "F.Cu")
		(net "M_A_CPU0_SA_DQS_DN<7>")
	)
	(arc
		(start 334.598518 -272.4277)
		(mid 334.477551 -272.316268)
		(end 334.415892 -272.163794)
		(width 0.088646)
		(layer "F.Cu")
		(net "M_A_CPU0_SA_DQS_DN<7>")
	)
	(arc
		(start 335.725262 -272.103342)
		(mid 335.532986 -272.128999)
		(end 335.354168 -272.20418)
		(width 0.088646)
		(layer "F.Cu")
		(net "M_A_CPU0_SA_DQS_DN<7>")
	)
	(arc
		(start 334.972914 -272.4277)
		(mid 334.785716 -272.477843)
		(end 334.598518 -272.4277)
		(width 0.088646)
		(layer "F.Cu")
		(net "M_A_CPU0_SA_DQS_DN<7>")
	)
	(segment
		(start 312.235596 -302.45558)
		(end 311.532016 -302.45558)
		(width 0.20066)
		(layer "F.Cu")
		(net "M_A_CPU0_SA_DQS_DN<6>")
	)
	(segment
		(start 307.764434 -302.301402)
		(end 307.76291 -302.301402)
		(width 0.101854)
		(layer "F.Cu")
		(net "M_A_CPU0_SA_DQS_DN<6>")
	)
	(segment
		(start 307.76291 -302.301402)
		(end 307.579776 -302.301402)
		(width 0.20066)
		(layer "F.Cu")
		(net "M_A_CPU0_SA_DQS_DN<6>")
	)
	(segment
		(start 314.092082 -302.716692)
		(end 312.987182 -302.716692)
		(width 0.20066)
		(layer "F.Cu")
		(net "M_A_CPU0_SA_DQS_DN<6>")
	)
	(segment
		(start 306.649374 -302.45558)
		(end 306.176172 -302.45558)
		(width 0.20066)
		(layer "F.Cu")
		(net "M_A_CPU0_SA_DQS_DN<6>")
	)
	(segment
		(start 310.491378 -302.030638)
		(end 310.230266 -302.29175)
		(width 0.20066)
		(layer "F.Cu")
		(net "M_A_CPU0_SA_DQS_DN<6>")
	)
	(segment
		(start 307.311552 -302.033178)
		(end 307.071776 -302.033178)
		(width 0.20066)
		(layer "F.Cu")
		(net "M_A_CPU0_SA_DQS_DN<6>")
	)
	(segment
		(start 312.496708 -302.716692)
		(end 312.235596 -302.45558)
		(width 0.20066)
		(layer "F.Cu")
		(net "M_A_CPU0_SA_DQS_DN<6>")
	)
	(segment
		(start 307.774086 -302.29175)
		(end 307.764434 -302.301402)
		(width 0.101854)
		(layer "F.Cu")
		(net "M_A_CPU0_SA_DQS_DN<6>")
	)
	(segment
		(start 307.579776 -302.301402)
		(end 307.311552 -302.033178)
		(width 0.20066)
		(layer "F.Cu")
		(net "M_A_CPU0_SA_DQS_DN<6>")
	)
	(segment
		(start 312.987182 -302.716692)
		(end 312.496708 -302.716692)
		(width 0.20066)
		(layer "F.Cu")
		(net "M_A_CPU0_SA_DQS_DN<6>")
	)
	(segment
		(start 310.230266 -302.29175)
		(end 310.088026 -302.29175)
		(width 0.20066)
		(layer "F.Cu")
		(net "M_A_CPU0_SA_DQS_DN<6>")
	)
	(segment
		(start 339.014562 -269.66164)
		(end 339.014562 -270.197326)
		(width 0.20066)
		(layer "F.Cu")
		(net "M_A_CPU0_SA_DQS_DN<6>")
	)
	(segment
		(start 339.014562 -270.197326)
		(end 339.014816 -270.19758)
		(width 0.20066)
		(layer "F.Cu")
		(net "M_A_CPU0_SA_DQS_DN<6>")
	)
	(segment
		(start 310.088026 -302.29175)
		(end 308.01056 -302.29175)
		(width 0.1016)
		(layer "F.Cu")
		(net "M_A_CPU0_SA_DQS_DN<6>")
	)
	(segment
		(start 305.91506 -302.716692)
		(end 305.443382 -302.716692)
		(width 0.20066)
		(layer "F.Cu")
		(net "M_A_CPU0_SA_DQS_DN<6>")
	)
	(segment
		(start 306.176172 -302.45558)
		(end 305.91506 -302.716692)
		(width 0.20066)
		(layer "F.Cu")
		(net "M_A_CPU0_SA_DQS_DN<6>")
	)
	(segment
		(start 308.01056 -302.29175)
		(end 307.774086 -302.29175)
		(width 0.101854)
		(layer "F.Cu")
		(net "M_A_CPU0_SA_DQS_DN<6>")
	)
	(segment
		(start 311.532016 -302.45558)
		(end 310.896 -302.030638)
		(width 0.20066)
		(layer "F.Cu")
		(net "M_A_CPU0_SA_DQS_DN<6>")
	)
	(segment
		(start 310.896 -302.030638)
		(end 310.491378 -302.030638)
		(width 0.20066)
		(layer "F.Cu")
		(net "M_A_CPU0_SA_DQS_DN<6>")
	)
	(segment
		(start 307.071776 -302.033178)
		(end 306.649374 -302.45558)
		(width 0.20066)
		(layer "F.Cu")
		(net "M_A_CPU0_SA_DQS_DN<6>")
	)
	(segment
		(start 316.601856 -295.777158)
		(end 316.601856 -295.777412)
		(width 0.18288)
		(layer "In2.Cu")
		(net "M_A_CPU0_SA_DQS_DN<6>")
	)
	(segment
		(start 337.33105 -269.878302)
		(end 337.32216 -269.873222)
		(width 0.088646)
		(layer "In2.Cu")
		(net "M_A_CPU0_SA_DQS_DN<6>")
	)
	(segment
		(start 330.092558 -273.375882)
		(end 328.869548 -276.328124)
		(width 0.18288)
		(layer "In2.Cu")
		(net "M_A_CPU0_SA_DQS_DN<6>")
	)
	(segment
		(start 332.662276 -270.721074)
		(end 332.573376 -270.809974)
		(width 0.088646)
		(layer "In2.Cu")
		(net "M_A_CPU0_SA_DQS_DN<6>")
	)
	(segment
		(start 332.573376 -270.809974)
		(end 332.573376 -270.895064)
		(width 0.088646)
		(layer "In2.Cu")
		(net "M_A_CPU0_SA_DQS_DN<6>")
	)
	(segment
		(start 316.113668 -296.956734)
		(end 315.931296 -297.395646)
		(width 0.18288)
		(layer "In2.Cu")
		(net "M_A_CPU0_SA_DQS_DN<6>")
	)
	(segment
		(start 328.869548 -276.328124)
		(end 324.574916 -280.622756)
		(width 0.18288)
		(layer "In2.Cu")
		(net "M_A_CPU0_SA_DQS_DN<6>")
	)
	(segment
		(start 315.199268 -302.01997)
		(end 314.784994 -302.434498)
		(width 0.18288)
		(layer "In2.Cu")
		(net "M_A_CPU0_SA_DQS_DN<6>")
	)
	(segment
		(start 316.259718 -295.919144)
		(end 315.971428 -296.614596)
		(width 0.18288)
		(layer "In2.Cu")
		(net "M_A_CPU0_SA_DQS_DN<6>")
	)
	(segment
		(start 334.785462 -269.948914)
		(end 334.676496 -269.948914)
		(width 0.088646)
		(layer "In2.Cu")
		(net "M_A_CPU0_SA_DQS_DN<6>")
	)
	(segment
		(start 332.573376 -270.895064)
		(end 330.092558 -273.375882)
		(width 0.18288)
		(layer "In2.Cu")
		(net "M_A_CPU0_SA_DQS_DN<6>")
	)
	(segment
		(start 315.931296 -297.395646)
		(end 315.931296 -300.25213)
		(width 0.18288)
		(layer "In2.Cu")
		(net "M_A_CPU0_SA_DQS_DN<6>")
	)
	(segment
		(start 338.701888 -270.19758)
		(end 338.636356 -270.263112)
		(width 0.088646)
		(layer "In2.Cu")
		(net "M_A_CPU0_SA_DQS_DN<6>")
	)
	(segment
		(start 315.931296 -300.25213)
		(end 315.199268 -302.01997)
		(width 0.18288)
		(layer "In2.Cu")
		(net "M_A_CPU0_SA_DQS_DN<6>")
	)
	(segment
		(start 314.374276 -302.434498)
		(end 314.092082 -302.716692)
		(width 0.18288)
		(layer "In2.Cu")
		(net "M_A_CPU0_SA_DQS_DN<6>")
	)
	(segment
		(start 324.574916 -280.622756)
		(end 323.559424 -283.074618)
		(width 0.18288)
		(layer "In2.Cu")
		(net "M_A_CPU0_SA_DQS_DN<6>")
	)
	(segment
		(start 320.660776 -285.97352)
		(end 316.601856 -295.777158)
		(width 0.18288)
		(layer "In2.Cu")
		(net "M_A_CPU0_SA_DQS_DN<6>")
	)
	(segment
		(start 334.676496 -269.948914)
		(end 333.912718 -270.712692)
		(width 0.088646)
		(layer "In2.Cu")
		(net "M_A_CPU0_SA_DQS_DN<6>")
	)
	(segment
		(start 314.784994 -302.434498)
		(end 314.374276 -302.434498)
		(width 0.18288)
		(layer "In2.Cu")
		(net "M_A_CPU0_SA_DQS_DN<6>")
	)
	(segment
		(start 337.509612 -270.207486)
		(end 337.509612 -270.19758)
		(width 0.088646)
		(layer "In2.Cu")
		(net "M_A_CPU0_SA_DQS_DN<6>")
	)
	(segment
		(start 323.559424 -283.074618)
		(end 320.660776 -285.97352)
		(width 0.18288)
		(layer "In2.Cu")
		(net "M_A_CPU0_SA_DQS_DN<6>")
	)
	(segment
		(start 333.912718 -270.712692)
		(end 332.682342 -270.712692)
		(width 0.088646)
		(layer "In2.Cu")
		(net "M_A_CPU0_SA_DQS_DN<6>")
	)
	(segment
		(start 339.014816 -270.19758)
		(end 338.701888 -270.19758)
		(width 0.088646)
		(layer "In2.Cu")
		(net "M_A_CPU0_SA_DQS_DN<6>")
	)
	(segment
		(start 332.663038 -270.72082)
		(end 332.662276 -270.721074)
		(width 0.088646)
		(layer "In2.Cu")
		(net "M_A_CPU0_SA_DQS_DN<6>")
	)
	(segment
		(start 332.682342 -270.712692)
		(end 332.663038 -270.72082)
		(width 0.088646)
		(layer "In2.Cu")
		(net "M_A_CPU0_SA_DQS_DN<6>")
	)
	(segment
		(start 315.971428 -296.614596)
		(end 316.113668 -296.956734)
		(width 0.18288)
		(layer "In2.Cu")
		(net "M_A_CPU0_SA_DQS_DN<6>")
	)
	(segment
		(start 316.601856 -295.777412)
		(end 316.259718 -295.919144)
		(width 0.18288)
		(layer "In2.Cu")
		(net "M_A_CPU0_SA_DQS_DN<6>")
	)
	(segment
		(start 338.369656 -270.679926)
		(end 338.357464 -270.687038)
		(width 0.088646)
		(layer "In2.Cu")
		(net "M_A_CPU0_SA_DQS_DN<6>")
	)
	(arc
		(start 338.636356 -270.263112)
		(mid 338.635055 -270.273539)
		(end 338.633562 -270.28394)
		(width 0.088646)
		(layer "In2.Cu")
		(net "M_A_CPU0_SA_DQS_DN<6>")
	)
	(arc
		(start 336.38236 -269.873222)
		(mid 336.195162 -269.823079)
		(end 336.007964 -269.873222)
		(width 0.088646)
		(layer "In2.Cu")
		(net "M_A_CPU0_SA_DQS_DN<6>")
	)
	(arc
		(start 336.947764 -269.873222)
		(mid 336.665062 -269.948964)
		(end 336.38236 -269.873222)
		(width 0.088646)
		(layer "In2.Cu")
		(net "M_A_CPU0_SA_DQS_DN<6>")
	)
	(arc
		(start 336.007964 -269.873222)
		(mid 335.725262 -269.948964)
		(end 335.44256 -269.873222)
		(width 0.088646)
		(layer "In2.Cu")
		(net "M_A_CPU0_SA_DQS_DN<6>")
	)
	(arc
		(start 335.068164 -269.873222)
		(mid 334.931794 -269.929675)
		(end 334.785462 -269.948914)
		(width 0.088646)
		(layer "In2.Cu")
		(net "M_A_CPU0_SA_DQS_DN<6>")
	)
	(arc
		(start 338.633562 -270.28394)
		(mid 338.545328 -270.511081)
		(end 338.369656 -270.679926)
		(width 0.088646)
		(layer "In2.Cu")
		(net "M_A_CPU0_SA_DQS_DN<6>")
	)
	(arc
		(start 335.44256 -269.873222)
		(mid 335.255362 -269.823079)
		(end 335.068164 -269.873222)
		(width 0.088646)
		(layer "In2.Cu")
		(net "M_A_CPU0_SA_DQS_DN<6>")
	)
	(arc
		(start 337.79206 -270.687038)
		(mid 337.587725 -270.484433)
		(end 337.509612 -270.207486)
		(width 0.088646)
		(layer "In2.Cu")
		(net "M_A_CPU0_SA_DQS_DN<6>")
	)
	(arc
		(start 337.509612 -270.19758)
		(mid 337.461933 -270.01468)
		(end 337.33105 -269.878302)
		(width 0.088646)
		(layer "In2.Cu")
		(net "M_A_CPU0_SA_DQS_DN<6>")
	)
	(arc
		(start 338.357464 -270.687038)
		(mid 338.074762 -270.762814)
		(end 337.79206 -270.687038)
		(width 0.088646)
		(layer "In2.Cu")
		(net "M_A_CPU0_SA_DQS_DN<6>")
	)
	(arc
		(start 337.32216 -269.873222)
		(mid 337.134962 -269.823079)
		(end 336.947764 -269.873222)
		(width 0.088646)
		(layer "In2.Cu")
		(net "M_A_CPU0_SA_DQS_DN<6>")
	)
	(segment
		(start 314.917582 -311.517538)
		(end 315.410088 -311.31383)
		(width 0.20066)
		(layer "F.Cu")
		(net "M_A_CPU0_SA_DQS_DN<5>")
	)
	(segment
		(start 332.9813 -277.61184)
		(end 333.12989 -277.46325)
		(width 0.088646)
		(layer "F.Cu")
		(net "M_A_CPU0_SA_DQS_DN<5>")
	)
	(segment
		(start 305.91506 -312.066686)
		(end 306.176172 -311.805574)
		(width 0.20066)
		(layer "F.Cu")
		(net "M_A_CPU0_SA_DQS_DN<5>")
	)
	(segment
		(start 310.088026 -311.651396)
		(end 310.385206 -311.651396)
		(width 0.20066)
		(layer "F.Cu")
		(net "M_A_CPU0_SA_DQS_DN<5>")
	)
	(segment
		(start 318.860424 -307.86324)
		(end 324.080378 -303.578768)
		(width 0.20066)
		(layer "F.Cu")
		(net "M_A_CPU0_SA_DQS_DN<5>")
	)
	(segment
		(start 307.76291 -311.651396)
		(end 307.764434 -311.651396)
		(width 0.1016)
		(layer "F.Cu")
		(net "M_A_CPU0_SA_DQS_DN<5>")
	)
	(segment
		(start 311.141872 -311.380632)
		(end 311.777888 -311.805574)
		(width 0.20066)
		(layer "F.Cu")
		(net "M_A_CPU0_SA_DQS_DN<5>")
	)
	(segment
		(start 330.482702 -297.01871)
		(end 330.92898 -295.93794)
		(width 0.1524)
		(layer "F.Cu")
		(net "M_A_CPU0_SA_DQS_DN<5>")
	)
	(segment
		(start 305.443382 -312.066686)
		(end 305.91506 -312.066686)
		(width 0.20066)
		(layer "F.Cu")
		(net "M_A_CPU0_SA_DQS_DN<5>")
	)
	(segment
		(start 330.92898 -282.353512)
		(end 331.498702 -279.489154)
		(width 0.1524)
		(layer "F.Cu")
		(net "M_A_CPU0_SA_DQS_DN<5>")
	)
	(segment
		(start 331.498702 -279.489154)
		(end 332.21676 -278.771096)
		(width 0.1524)
		(layer "F.Cu")
		(net "M_A_CPU0_SA_DQS_DN<5>")
	)
	(segment
		(start 332.232254 -278.755602)
		(end 332.232254 -278.71039)
		(width 0.088646)
		(layer "F.Cu")
		(net "M_A_CPU0_SA_DQS_DN<5>")
	)
	(segment
		(start 314.226194 -311.803542)
		(end 314.917582 -311.517538)
		(width 0.20066)
		(layer "F.Cu")
		(net "M_A_CPU0_SA_DQS_DN<5>")
	)
	(segment
		(start 329.998832 -297.660314)
		(end 330.025756 -297.63339)
		(width 0.1524)
		(layer "F.Cu")
		(net "M_A_CPU0_SA_DQS_DN<5>")
	)
	(segment
		(start 335.816702 -277.868126)
		(end 335.884266 -277.800562)
		(width 0.088646)
		(layer "F.Cu")
		(net "M_A_CPU0_SA_DQS_DN<5>")
	)
	(segment
		(start 306.176172 -311.805574)
		(end 306.53863 -311.805574)
		(width 0.20066)
		(layer "F.Cu")
		(net "M_A_CPU0_SA_DQS_DN<5>")
	)
	(segment
		(start 330.025756 -297.63339)
		(end 330.025756 -297.581066)
		(width 0.1524)
		(layer "F.Cu")
		(net "M_A_CPU0_SA_DQS_DN<5>")
	)
	(segment
		(start 310.077358 -311.651396)
		(end 310.088026 -311.651396)
		(width 0.1016)
		(layer "F.Cu")
		(net "M_A_CPU0_SA_DQS_DN<5>")
	)
	(segment
		(start 311.777888 -311.805574)
		(end 312.235596 -311.805574)
		(width 0.20066)
		(layer "F.Cu")
		(net "M_A_CPU0_SA_DQS_DN<5>")
	)
	(segment
		(start 333.220568 -277.425404)
		(end 333.375762 -277.425404)
		(width 0.088646)
		(layer "F.Cu")
		(net "M_A_CPU0_SA_DQS_DN<5>")
	)
	(segment
		(start 332.90129 -277.804626)
		(end 332.9813 -277.61184)
		(width 0.088646)
		(layer "F.Cu")
		(net "M_A_CPU0_SA_DQS_DN<5>")
	)
	(segment
		(start 334.972914 -278.29002)
		(end 334.983328 -278.296116)
		(width 0.088646)
		(layer "F.Cu")
		(net "M_A_CPU0_SA_DQS_DN<5>")
	)
	(segment
		(start 310.385206 -311.651396)
		(end 310.65597 -311.380632)
		(width 0.20066)
		(layer "F.Cu")
		(net "M_A_CPU0_SA_DQS_DN<5>")
	)
	(segment
		(start 307.38826 -311.651396)
		(end 307.76291 -311.651396)
		(width 0.20066)
		(layer "F.Cu")
		(net "M_A_CPU0_SA_DQS_DN<5>")
	)
	(segment
		(start 334.966818 -278.286464)
		(end 334.972152 -278.289512)
		(width 0.088646)
		(layer "F.Cu")
		(net "M_A_CPU0_SA_DQS_DN<5>")
	)
	(segment
		(start 306.961032 -311.383172)
		(end 307.120036 -311.383172)
		(width 0.20066)
		(layer "F.Cu")
		(net "M_A_CPU0_SA_DQS_DN<5>")
	)
	(segment
		(start 310.067706 -311.641744)
		(end 310.077358 -311.651396)
		(width 0.1016)
		(layer "F.Cu")
		(net "M_A_CPU0_SA_DQS_DN<5>")
	)
	(segment
		(start 306.53863 -311.805574)
		(end 306.961032 -311.383172)
		(width 0.20066)
		(layer "F.Cu")
		(net "M_A_CPU0_SA_DQS_DN<5>")
	)
	(segment
		(start 334.972152 -278.289512)
		(end 334.972914 -278.29002)
		(width 0.088646)
		(layer "F.Cu")
		(net "M_A_CPU0_SA_DQS_DN<5>")
	)
	(segment
		(start 307.774086 -311.641744)
		(end 310.067706 -311.641744)
		(width 0.1016)
		(layer "F.Cu")
		(net "M_A_CPU0_SA_DQS_DN<5>")
	)
	(segment
		(start 335.884266 -277.800562)
		(end 336.195162 -277.800562)
		(width 0.088646)
		(layer "F.Cu")
		(net "M_A_CPU0_SA_DQS_DN<5>")
	)
	(segment
		(start 310.65597 -311.380632)
		(end 311.141872 -311.380632)
		(width 0.20066)
		(layer "F.Cu")
		(net "M_A_CPU0_SA_DQS_DN<5>")
	)
	(segment
		(start 312.235596 -311.805574)
		(end 312.496708 -312.066686)
		(width 0.20066)
		(layer "F.Cu")
		(net "M_A_CPU0_SA_DQS_DN<5>")
	)
	(segment
		(start 315.410088 -311.31383)
		(end 318.860424 -307.86324)
		(width 0.20066)
		(layer "F.Cu")
		(net "M_A_CPU0_SA_DQS_DN<5>")
	)
	(segment
		(start 330.025756 -297.581066)
		(end 330.27112 -297.335702)
		(width 0.1524)
		(layer "F.Cu")
		(net "M_A_CPU0_SA_DQS_DN<5>")
	)
	(segment
		(start 333.12989 -277.46325)
		(end 333.220568 -277.425404)
		(width 0.088646)
		(layer "F.Cu")
		(net "M_A_CPU0_SA_DQS_DN<5>")
	)
	(segment
		(start 332.21676 -278.771096)
		(end 332.232254 -278.755602)
		(width 0.088646)
		(layer "F.Cu")
		(net "M_A_CPU0_SA_DQS_DN<5>")
	)
	(segment
		(start 324.080378 -303.578768)
		(end 329.998832 -297.660314)
		(width 0.20066)
		(layer "F.Cu")
		(net "M_A_CPU0_SA_DQS_DN<5>")
	)
	(segment
		(start 312.496708 -312.066686)
		(end 312.987182 -312.066686)
		(width 0.20066)
		(layer "F.Cu")
		(net "M_A_CPU0_SA_DQS_DN<5>")
	)
	(segment
		(start 313.816746 -311.803542)
		(end 314.226194 -311.803542)
		(width 0.20066)
		(layer "F.Cu")
		(net "M_A_CPU0_SA_DQS_DN<5>")
	)
	(segment
		(start 332.328266 -278.614378)
		(end 332.444598 -278.261318)
		(width 0.088646)
		(layer "F.Cu")
		(net "M_A_CPU0_SA_DQS_DN<5>")
	)
	(segment
		(start 330.27112 -297.335702)
		(end 330.482702 -297.01871)
		(width 0.1524)
		(layer "F.Cu")
		(net "M_A_CPU0_SA_DQS_DN<5>")
	)
	(segment
		(start 307.764434 -311.651396)
		(end 307.774086 -311.641744)
		(width 0.1016)
		(layer "F.Cu")
		(net "M_A_CPU0_SA_DQS_DN<5>")
	)
	(segment
		(start 330.92898 -295.93794)
		(end 330.92898 -282.353512)
		(width 0.1524)
		(layer "F.Cu")
		(net "M_A_CPU0_SA_DQS_DN<5>")
	)
	(segment
		(start 332.444598 -278.261318)
		(end 332.90129 -277.804626)
		(width 0.088646)
		(layer "F.Cu")
		(net "M_A_CPU0_SA_DQS_DN<5>")
	)
	(segment
		(start 334.50276 -277.476204)
		(end 334.51165 -277.481284)
		(width 0.088646)
		(layer "F.Cu")
		(net "M_A_CPU0_SA_DQS_DN<5>")
	)
	(segment
		(start 313.553602 -312.066686)
		(end 313.816746 -311.803542)
		(width 0.20066)
		(layer "F.Cu")
		(net "M_A_CPU0_SA_DQS_DN<5>")
	)
	(segment
		(start 307.120036 -311.383172)
		(end 307.38826 -311.651396)
		(width 0.20066)
		(layer "F.Cu")
		(net "M_A_CPU0_SA_DQS_DN<5>")
	)
	(segment
		(start 332.232254 -278.71039)
		(end 332.328266 -278.614378)
		(width 0.088646)
		(layer "F.Cu")
		(net "M_A_CPU0_SA_DQS_DN<5>")
	)
	(segment
		(start 312.987182 -312.066686)
		(end 313.553602 -312.066686)
		(width 0.20066)
		(layer "F.Cu")
		(net "M_A_CPU0_SA_DQS_DN<5>")
	)
	(arc
		(start 335.813654 -277.889716)
		(mid 335.815284 -277.878936)
		(end 335.816702 -277.868126)
		(width 0.088646)
		(layer "F.Cu")
		(net "M_A_CPU0_SA_DQS_DN<5>")
	)
	(arc
		(start 334.690212 -277.800562)
		(mid 334.764203 -278.080128)
		(end 334.966818 -278.286464)
		(width 0.088646)
		(layer "F.Cu")
		(net "M_A_CPU0_SA_DQS_DN<5>")
	)
	(arc
		(start 333.56296 -277.476204)
		(mid 333.845662 -277.551946)
		(end 334.128364 -277.476204)
		(width 0.088646)
		(layer "F.Cu")
		(net "M_A_CPU0_SA_DQS_DN<5>")
	)
	(arc
		(start 334.689958 -277.78583)
		(mid 334.690155 -277.793195)
		(end 334.690212 -277.800562)
		(width 0.088646)
		(layer "F.Cu")
		(net "M_A_CPU0_SA_DQS_DN<5>")
	)
	(arc
		(start 335.538064 -278.29002)
		(mid 335.721086 -278.121005)
		(end 335.813654 -277.889716)
		(width 0.088646)
		(layer "F.Cu")
		(net "M_A_CPU0_SA_DQS_DN<5>")
	)
	(arc
		(start 334.51165 -277.481284)
		(mid 334.638904 -277.61125)
		(end 334.689958 -277.78583)
		(width 0.088646)
		(layer "F.Cu")
		(net "M_A_CPU0_SA_DQS_DN<5>")
	)
	(arc
		(start 334.128364 -277.476204)
		(mid 334.315562 -277.426061)
		(end 334.50276 -277.476204)
		(width 0.088646)
		(layer "F.Cu")
		(net "M_A_CPU0_SA_DQS_DN<5>")
	)
	(arc
		(start 334.983328 -278.296116)
		(mid 335.261506 -278.365839)
		(end 335.538064 -278.29002)
		(width 0.088646)
		(layer "F.Cu")
		(net "M_A_CPU0_SA_DQS_DN<5>")
	)
	(arc
		(start 333.375762 -277.425404)
		(mid 333.472701 -277.438494)
		(end 333.56296 -277.476204)
		(width 0.088646)
		(layer "F.Cu")
		(net "M_A_CPU0_SA_DQS_DN<5>")
	)
	(segment
		(start 331.436726 -262.690102)
		(end 331.347826 -262.601202)
		(width 0.088646)
		(layer "F.Cu")
		(net "M_A_CPU0_SA_DQS_DN<4>")
	)
	(segment
		(start 322.419726 -269.886176)
		(end 321.994276 -270.311626)
		(width 0.20066)
		(layer "F.Cu")
		(net "M_A_CPU0_SA_DQS_DN<4>")
	)
	(segment
		(start 301.343314 -274.66671)
		(end 301.891954 -274.66671)
		(width 0.20066)
		(layer "F.Cu")
		(net "M_A_CPU0_SA_DQS_DN<4>")
	)
	(segment
		(start 320.364866 -271.765014)
		(end 320.364866 -271.941036)
		(width 0.20066)
		(layer "F.Cu")
		(net "M_A_CPU0_SA_DQS_DN<4>")
	)
	(segment
		(start 332.906116 -262.336534)
		(end 332.730094 -262.512556)
		(width 0.088646)
		(layer "F.Cu")
		(net "M_A_CPU0_SA_DQS_DN<4>")
	)
	(segment
		(start 324.754748 -268.184122)
		(end 324.173596 -268.184122)
		(width 0.1524)
		(layer "F.Cu")
		(net "M_A_CPU0_SA_DQS_DN<4>")
	)
	(segment
		(start 306.68468 -275.091652)
		(end 306.799488 -275.091652)
		(width 0.20066)
		(layer "F.Cu")
		(net "M_A_CPU0_SA_DQS_DN<4>")
	)
	(segment
		(start 332.301596 -262.690102)
		(end 332.108556 -262.690102)
		(width 0.088646)
		(layer "F.Cu")
		(net "M_A_CPU0_SA_DQS_DN<4>")
	)
	(segment
		(start 323.525896 -268.831822)
		(end 323.47408 -268.831822)
		(width 0.1524)
		(layer "F.Cu")
		(net "M_A_CPU0_SA_DQS_DN<4>")
	)
	(segment
		(start 330.280518 -262.658352)
		(end 324.754748 -268.184122)
		(width 0.1524)
		(layer "F.Cu")
		(net "M_A_CPU0_SA_DQS_DN<4>")
	)
	(segment
		(start 321.392296 -270.737584)
		(end 321.392296 -270.913606)
		(width 0.20066)
		(layer "F.Cu")
		(net "M_A_CPU0_SA_DQS_DN<4>")
	)
	(segment
		(start 320.966846 -271.339056)
		(end 320.790824 -271.339056)
		(width 0.20066)
		(layer "F.Cu")
		(net "M_A_CPU0_SA_DQS_DN<4>")
	)
	(segment
		(start 311.388506 -275.359114)
		(end 310.86298 -275.359114)
		(width 0.20066)
		(layer "F.Cu")
		(net "M_A_CPU0_SA_DQS_DN<4>")
	)
	(segment
		(start 308.340506 -274.66671)
		(end 308.887114 -274.66671)
		(width 0.20066)
		(layer "F.Cu")
		(net "M_A_CPU0_SA_DQS_DN<4>")
	)
	(segment
		(start 330.72832 -262.690102)
		(end 330.69657 -262.658352)
		(width 0.088646)
		(layer "F.Cu")
		(net "M_A_CPU0_SA_DQS_DN<4>")
	)
	(segment
		(start 321.392296 -270.913606)
		(end 320.966846 -271.339056)
		(width 0.20066)
		(layer "F.Cu")
		(net "M_A_CPU0_SA_DQS_DN<4>")
	)
	(segment
		(start 302.51908 -274.927822)
		(end 303.155096 -275.353018)
		(width 0.20066)
		(layer "F.Cu")
		(net "M_A_CPU0_SA_DQS_DN<4>")
	)
	(segment
		(start 307.67274 -274.927822)
		(end 308.079394 -274.927822)
		(width 0.20066)
		(layer "F.Cu")
		(net "M_A_CPU0_SA_DQS_DN<4>")
	)
	(segment
		(start 303.155096 -275.353018)
		(end 303.623472 -275.353018)
		(width 0.20066)
		(layer "F.Cu")
		(net "M_A_CPU0_SA_DQS_DN<4>")
	)
	(segment
		(start 301.891954 -274.66671)
		(end 302.153066 -274.927822)
		(width 0.20066)
		(layer "F.Cu")
		(net "M_A_CPU0_SA_DQS_DN<4>")
	)
	(segment
		(start 322.845684 -269.284196)
		(end 322.419726 -269.710154)
		(width 0.20066)
		(layer "F.Cu")
		(net "M_A_CPU0_SA_DQS_DN<4>")
	)
	(segment
		(start 311.655968 -275.091652)
		(end 311.388506 -275.359114)
		(width 0.20066)
		(layer "F.Cu")
		(net "M_A_CPU0_SA_DQS_DN<4>")
	)
	(segment
		(start 315.983112 -275.472652)
		(end 314.604654 -275.472652)
		(width 0.20066)
		(layer "F.Cu")
		(net "M_A_CPU0_SA_DQS_DN<4>")
	)
	(segment
		(start 303.976532 -275.091652)
		(end 306.68468 -275.091652)
		(width 0.1016)
		(layer "F.Cu")
		(net "M_A_CPU0_SA_DQS_DN<4>")
	)
	(segment
		(start 318.735964 -273.393916)
		(end 318.310006 -273.819874)
		(width 0.20066)
		(layer "F.Cu")
		(net "M_A_CPU0_SA_DQS_DN<4>")
	)
	(segment
		(start 323.447156 -268.858746)
		(end 323.021706 -269.284196)
		(width 0.20066)
		(layer "F.Cu")
		(net "M_A_CPU0_SA_DQS_DN<4>")
	)
	(segment
		(start 307.31968 -275.280882)
		(end 307.67274 -274.927822)
		(width 0.20066)
		(layer "F.Cu")
		(net "M_A_CPU0_SA_DQS_DN<4>")
	)
	(segment
		(start 331.14742 -262.601202)
		(end 331.05852 -262.690102)
		(width 0.088646)
		(layer "F.Cu")
		(net "M_A_CPU0_SA_DQS_DN<4>")
	)
	(segment
		(start 331.347826 -262.601202)
		(end 331.14742 -262.601202)
		(width 0.088646)
		(layer "F.Cu")
		(net "M_A_CPU0_SA_DQS_DN<4>")
	)
	(segment
		(start 318.911986 -273.393916)
		(end 318.735964 -273.393916)
		(width 0.20066)
		(layer "F.Cu")
		(net "M_A_CPU0_SA_DQS_DN<4>")
	)
	(segment
		(start 314.505848 -275.373846)
		(end 314.505848 -275.194522)
		(width 0.20066)
		(layer "F.Cu")
		(net "M_A_CPU0_SA_DQS_DN<4>")
	)
	(segment
		(start 319.939416 -272.366486)
		(end 319.763394 -272.366486)
		(width 0.20066)
		(layer "F.Cu")
		(net "M_A_CPU0_SA_DQS_DN<4>")
	)
	(segment
		(start 331.05852 -262.690102)
		(end 330.72832 -262.690102)
		(width 0.088646)
		(layer "F.Cu")
		(net "M_A_CPU0_SA_DQS_DN<4>")
	)
	(segment
		(start 309.381398 -274.66671)
		(end 308.887114 -274.66671)
		(width 0.20066)
		(layer "F.Cu")
		(net "M_A_CPU0_SA_DQS_DN<4>")
	)
	(segment
		(start 320.364866 -271.941036)
		(end 319.939416 -272.366486)
		(width 0.20066)
		(layer "F.Cu")
		(net "M_A_CPU0_SA_DQS_DN<4>")
	)
	(segment
		(start 302.153066 -274.927822)
		(end 302.51908 -274.927822)
		(width 0.20066)
		(layer "F.Cu")
		(net "M_A_CPU0_SA_DQS_DN<4>")
	)
	(segment
		(start 322.419726 -269.710154)
		(end 322.419726 -269.886176)
		(width 0.20066)
		(layer "F.Cu")
		(net "M_A_CPU0_SA_DQS_DN<4>")
	)
	(segment
		(start 319.763394 -272.366486)
		(end 319.337436 -272.792444)
		(width 0.20066)
		(layer "F.Cu")
		(net "M_A_CPU0_SA_DQS_DN<4>")
	)
	(segment
		(start 314.604654 -275.472652)
		(end 314.505848 -275.373846)
		(width 0.20066)
		(layer "F.Cu")
		(net "M_A_CPU0_SA_DQS_DN<4>")
	)
	(segment
		(start 311.75579 -275.091652)
		(end 311.655968 -275.091652)
		(width 0.20066)
		(layer "F.Cu")
		(net "M_A_CPU0_SA_DQS_DN<4>")
	)
	(segment
		(start 307.060854 -275.353018)
		(end 307.145944 -275.353018)
		(width 0.20066)
		(layer "F.Cu")
		(net "M_A_CPU0_SA_DQS_DN<4>")
	)
	(segment
		(start 307.145944 -275.353018)
		(end 307.31968 -275.280882)
		(width 0.20066)
		(layer "F.Cu")
		(net "M_A_CPU0_SA_DQS_DN<4>")
	)
	(segment
		(start 317.9064 -274.399502)
		(end 316.81801 -275.126704)
		(width 0.20066)
		(layer "F.Cu")
		(net "M_A_CPU0_SA_DQS_DN<4>")
	)
	(segment
		(start 314.505848 -275.194522)
		(end 314.402978 -275.091652)
		(width 0.20066)
		(layer "F.Cu")
		(net "M_A_CPU0_SA_DQS_DN<4>")
	)
	(segment
		(start 332.108556 -262.690102)
		(end 332.019656 -262.601202)
		(width 0.088646)
		(layer "F.Cu")
		(net "M_A_CPU0_SA_DQS_DN<4>")
	)
	(segment
		(start 320.790824 -271.339056)
		(end 320.364866 -271.765014)
		(width 0.20066)
		(layer "F.Cu")
		(net "M_A_CPU0_SA_DQS_DN<4>")
	)
	(segment
		(start 309.84571 -274.937728)
		(end 309.652924 -274.937728)
		(width 0.20066)
		(layer "F.Cu")
		(net "M_A_CPU0_SA_DQS_DN<4>")
	)
	(segment
		(start 319.337436 -272.968466)
		(end 318.911986 -273.393916)
		(width 0.20066)
		(layer "F.Cu")
		(net "M_A_CPU0_SA_DQS_DN<4>")
	)
	(segment
		(start 330.674472 -262.658352)
		(end 330.280518 -262.658352)
		(width 0.1524)
		(layer "F.Cu")
		(net "M_A_CPU0_SA_DQS_DN<4>")
	)
	(segment
		(start 316.81801 -275.126704)
		(end 315.983112 -275.472652)
		(width 0.20066)
		(layer "F.Cu")
		(net "M_A_CPU0_SA_DQS_DN<4>")
	)
	(segment
		(start 332.730094 -262.512556)
		(end 332.301596 -262.690102)
		(width 0.088646)
		(layer "F.Cu")
		(net "M_A_CPU0_SA_DQS_DN<4>")
	)
	(segment
		(start 308.079394 -274.927822)
		(end 308.340506 -274.66671)
		(width 0.20066)
		(layer "F.Cu")
		(net "M_A_CPU0_SA_DQS_DN<4>")
	)
	(segment
		(start 309.381652 -274.666456)
		(end 309.381398 -274.66671)
		(width 0.20066)
		(layer "F.Cu")
		(net "M_A_CPU0_SA_DQS_DN<4>")
	)
	(segment
		(start 321.994276 -270.311626)
		(end 321.818254 -270.311626)
		(width 0.20066)
		(layer "F.Cu")
		(net "M_A_CPU0_SA_DQS_DN<4>")
	)
	(segment
		(start 318.310006 -273.819874)
		(end 318.310006 -273.995896)
		(width 0.20066)
		(layer "F.Cu")
		(net "M_A_CPU0_SA_DQS_DN<4>")
	)
	(segment
		(start 331.81925 -262.601202)
		(end 331.73035 -262.690102)
		(width 0.088646)
		(layer "F.Cu")
		(net "M_A_CPU0_SA_DQS_DN<4>")
	)
	(segment
		(start 331.73035 -262.690102)
		(end 331.436726 -262.690102)
		(width 0.088646)
		(layer "F.Cu")
		(net "M_A_CPU0_SA_DQS_DN<4>")
	)
	(segment
		(start 310.86298 -275.359114)
		(end 309.84571 -274.937728)
		(width 0.20066)
		(layer "F.Cu")
		(net "M_A_CPU0_SA_DQS_DN<4>")
	)
	(segment
		(start 332.019656 -262.601202)
		(end 331.81925 -262.601202)
		(width 0.088646)
		(layer "F.Cu")
		(net "M_A_CPU0_SA_DQS_DN<4>")
	)
	(segment
		(start 314.248292 -275.091652)
		(end 311.75579 -275.091652)
		(width 0.1016)
		(layer "F.Cu")
		(net "M_A_CPU0_SA_DQS_DN<4>")
	)
	(segment
		(start 321.818254 -270.311626)
		(end 321.392296 -270.737584)
		(width 0.20066)
		(layer "F.Cu")
		(net "M_A_CPU0_SA_DQS_DN<4>")
	)
	(segment
		(start 314.402978 -275.091652)
		(end 314.248292 -275.091652)
		(width 0.20066)
		(layer "F.Cu")
		(net "M_A_CPU0_SA_DQS_DN<4>")
	)
	(segment
		(start 323.47408 -268.831822)
		(end 323.447156 -268.858746)
		(width 0.1524)
		(layer "F.Cu")
		(net "M_A_CPU0_SA_DQS_DN<4>")
	)
	(segment
		(start 319.337436 -272.792444)
		(end 319.337436 -272.968466)
		(width 0.20066)
		(layer "F.Cu")
		(net "M_A_CPU0_SA_DQS_DN<4>")
	)
	(segment
		(start 318.310006 -273.995896)
		(end 317.9064 -274.399502)
		(width 0.20066)
		(layer "F.Cu")
		(net "M_A_CPU0_SA_DQS_DN<4>")
	)
	(segment
		(start 330.69657 -262.658352)
		(end 330.674472 -262.658352)
		(width 0.088646)
		(layer "F.Cu")
		(net "M_A_CPU0_SA_DQS_DN<4>")
	)
	(segment
		(start 323.021706 -269.284196)
		(end 322.845684 -269.284196)
		(width 0.20066)
		(layer "F.Cu")
		(net "M_A_CPU0_SA_DQS_DN<4>")
	)
	(segment
		(start 306.799488 -275.091652)
		(end 307.060854 -275.353018)
		(width 0.20066)
		(layer "F.Cu")
		(net "M_A_CPU0_SA_DQS_DN<4>")
	)
	(segment
		(start 303.623472 -275.353018)
		(end 303.884838 -275.091652)
		(width 0.20066)
		(layer "F.Cu")
		(net "M_A_CPU0_SA_DQS_DN<4>")
	)
	(segment
		(start 324.173596 -268.184122)
		(end 323.525896 -268.831822)
		(width 0.1524)
		(layer "F.Cu")
		(net "M_A_CPU0_SA_DQS_DN<4>")
	)
	(segment
		(start 309.652924 -274.937728)
		(end 309.381652 -274.666456)
		(width 0.20066)
		(layer "F.Cu")
		(net "M_A_CPU0_SA_DQS_DN<4>")
	)
	(segment
		(start 303.884838 -275.091652)
		(end 303.976532 -275.091652)
		(width 0.20066)
		(layer "F.Cu")
		(net "M_A_CPU0_SA_DQS_DN<4>")
	)
	(segment
		(start 330.92644 -269.150338)
		(end 330.881736 -269.150338)
		(width 0.088646)
		(layer "F.Cu")
		(net "M_A_CPU0_SA_DQS_DN<3>")
	)
	(segment
		(start 316.154054 -284.919166)
		(end 316.029594 -284.794706)
		(width 0.20066)
		(layer "F.Cu")
		(net "M_A_CPU0_SA_DQS_DN<3>")
	)
	(segment
		(start 323.62521 -280.14295)
		(end 323.62521 -280.143458)
		(width 0.1524)
		(layer "F.Cu")
		(net "M_A_CPU0_SA_DQS_DN<3>")
	)
	(segment
		(start 314.728098 -284.52699)
		(end 314.625228 -284.42412)
		(width 0.20066)
		(layer "F.Cu")
		(net "M_A_CPU0_SA_DQS_DN<3>")
	)
	(segment
		(start 320.144902 -284.482794)
		(end 319.48755 -284.61335)
		(width 0.20066)
		(layer "F.Cu")
		(net "M_A_CPU0_SA_DQS_DN<3>")
	)
	(segment
		(start 311.479692 -284.424882)
		(end 311.195466 -284.709108)
		(width 0.20066)
		(layer "F.Cu")
		(net "M_A_CPU0_SA_DQS_DN<3>")
	)
	(segment
		(start 321.2465 -283.381196)
		(end 321.070478 -283.381196)
		(width 0.20066)
		(layer "F.Cu")
		(net "M_A_CPU0_SA_DQS_DN<3>")
	)
	(segment
		(start 311.908444 -284.441646)
		(end 311.89168 -284.424882)
		(width 0.1016)
		(layer "F.Cu")
		(net "M_A_CPU0_SA_DQS_DN<3>")
	)
	(segment
		(start 330.866242 -269.165832)
		(end 325.561706 -274.470368)
		(width 0.1524)
		(layer "F.Cu")
		(net "M_A_CPU0_SA_DQS_DN<3>")
	)
	(segment
		(start 332.45171 -267.647166)
		(end 332.271878 -267.826998)
		(width 0.088646)
		(layer "F.Cu")
		(net "M_A_CPU0_SA_DQS_DN<3>")
	)
	(segment
		(start 302.70577 -284.277816)
		(end 303.341786 -284.703012)
		(width 0.20066)
		(layer "F.Cu")
		(net "M_A_CPU0_SA_DQS_DN<3>")
	)
	(segment
		(start 306.634896 -284.441646)
		(end 306.644294 -284.441646)
		(width 0.101854)
		(layer "F.Cu")
		(net "M_A_CPU0_SA_DQS_DN<3>")
	)
	(segment
		(start 318.750696 -284.633162)
		(end 318.652906 -284.77972)
		(width 0.20066)
		(layer "F.Cu")
		(net "M_A_CPU0_SA_DQS_DN<3>")
	)
	(segment
		(start 316.756034 -284.919166)
		(end 316.154054 -284.919166)
		(width 0.20066)
		(layer "F.Cu")
		(net "M_A_CPU0_SA_DQS_DN<3>")
	)
	(segment
		(start 321.070478 -283.381196)
		(end 320.64452 -283.807154)
		(width 0.20066)
		(layer "F.Cu")
		(net "M_A_CPU0_SA_DQS_DN<3>")
	)
	(segment
		(start 306.833016 -284.441646)
		(end 307.094382 -284.703012)
		(width 0.20066)
		(layer "F.Cu")
		(net "M_A_CPU0_SA_DQS_DN<3>")
	)
	(segment
		(start 302.153066 -284.277816)
		(end 302.70577 -284.277816)
		(width 0.20066)
		(layer "F.Cu")
		(net "M_A_CPU0_SA_DQS_DN<3>")
	)
	(segment
		(start 317.606934 -284.919166)
		(end 317.482474 -284.794706)
		(width 0.20066)
		(layer "F.Cu")
		(net "M_A_CPU0_SA_DQS_DN<3>")
	)
	(segment
		(start 315.427614 -284.794706)
		(end 315.303154 -284.919166)
		(width 0.20066)
		(layer "F.Cu")
		(net "M_A_CPU0_SA_DQS_DN<3>")
	)
	(segment
		(start 321.67195 -282.779724)
		(end 321.67195 -282.955746)
		(width 0.20066)
		(layer "F.Cu")
		(net "M_A_CPU0_SA_DQS_DN<3>")
	)
	(segment
		(start 308.340506 -284.016704)
		(end 308.887114 -284.016704)
		(width 0.20066)
		(layer "F.Cu")
		(net "M_A_CPU0_SA_DQS_DN<3>")
	)
	(segment
		(start 330.881736 -269.150338)
		(end 330.866242 -269.165832)
		(width 0.088646)
		(layer "F.Cu")
		(net "M_A_CPU0_SA_DQS_DN<3>")
	)
	(segment
		(start 316.880494 -284.794706)
		(end 316.756034 -284.919166)
		(width 0.20066)
		(layer "F.Cu")
		(net "M_A_CPU0_SA_DQS_DN<3>")
	)
	(segment
		(start 331.973174 -268.125702)
		(end 331.793342 -268.305534)
		(width 0.088646)
		(layer "F.Cu")
		(net "M_A_CPU0_SA_DQS_DN<3>")
	)
	(segment
		(start 321.67195 -282.955746)
		(end 321.2465 -283.381196)
		(width 0.20066)
		(layer "F.Cu")
		(net "M_A_CPU0_SA_DQS_DN<3>")
	)
	(segment
		(start 309.381652 -284.01645)
		(end 309.381398 -284.016704)
		(width 0.20066)
		(layer "F.Cu")
		(net "M_A_CPU0_SA_DQS_DN<3>")
	)
	(segment
		(start 309.9943 -284.287722)
		(end 309.652924 -284.287722)
		(width 0.20066)
		(layer "F.Cu")
		(net "M_A_CPU0_SA_DQS_DN<3>")
	)
	(segment
		(start 314.914026 -284.919166)
		(end 314.728098 -284.733238)
		(width 0.20066)
		(layer "F.Cu")
		(net "M_A_CPU0_SA_DQS_DN<3>")
	)
	(segment
		(start 332.750668 -267.487654)
		(end 332.69555 -267.542772)
		(width 0.088646)
		(layer "F.Cu")
		(net "M_A_CPU0_SA_DQS_DN<3>")
	)
	(segment
		(start 303.650396 -284.703012)
		(end 303.92243 -284.430978)
		(width 0.20066)
		(layer "F.Cu")
		(net "M_A_CPU0_SA_DQS_DN<3>")
	)
	(segment
		(start 324.274688 -276.878034)
		(end 323.62521 -280.14295)
		(width 0.1524)
		(layer "F.Cu")
		(net "M_A_CPU0_SA_DQS_DN<3>")
	)
	(segment
		(start 325.561706 -274.470368)
		(end 324.274688 -276.878034)
		(width 0.1524)
		(layer "F.Cu")
		(net "M_A_CPU0_SA_DQS_DN<3>")
	)
	(segment
		(start 307.356256 -284.703012)
		(end 307.781452 -284.277816)
		(width 0.20066)
		(layer "F.Cu")
		(net "M_A_CPU0_SA_DQS_DN<3>")
	)
	(segment
		(start 317.482474 -284.794706)
		(end 316.880494 -284.794706)
		(width 0.20066)
		(layer "F.Cu")
		(net "M_A_CPU0_SA_DQS_DN<3>")
	)
	(segment
		(start 314.17768 -284.42412)
		(end 314.160154 -284.441646)
		(width 0.1016)
		(layer "F.Cu")
		(net "M_A_CPU0_SA_DQS_DN<3>")
	)
	(segment
		(start 332.271878 -267.966952)
		(end 332.113128 -268.125702)
		(width 0.088646)
		(layer "F.Cu")
		(net "M_A_CPU0_SA_DQS_DN<3>")
	)
	(segment
		(start 331.793342 -268.305534)
		(end 331.793342 -268.445488)
		(width 0.088646)
		(layer "F.Cu")
		(net "M_A_CPU0_SA_DQS_DN<3>")
	)
	(segment
		(start 303.92243 -284.430978)
		(end 304.319178 -284.430978)
		(width 0.20066)
		(layer "F.Cu")
		(net "M_A_CPU0_SA_DQS_DN<3>")
	)
	(segment
		(start 317.951358 -284.919166)
		(end 317.606934 -284.919166)
		(width 0.20066)
		(layer "F.Cu")
		(net "M_A_CPU0_SA_DQS_DN<3>")
	)
	(segment
		(start 314.160154 -284.441646)
		(end 311.908444 -284.441646)
		(width 0.1016)
		(layer "F.Cu")
		(net "M_A_CPU0_SA_DQS_DN<3>")
	)
	(segment
		(start 322.27393 -282.353766)
		(end 322.097908 -282.353766)
		(width 0.20066)
		(layer "F.Cu")
		(net "M_A_CPU0_SA_DQS_DN<3>")
	)
	(segment
		(start 304.330608 -284.441646)
		(end 306.634896 -284.441646)
		(width 0.1016)
		(layer "F.Cu")
		(net "M_A_CPU0_SA_DQS_DN<3>")
	)
	(segment
		(start 332.113128 -268.125702)
		(end 331.973174 -268.125702)
		(width 0.088646)
		(layer "F.Cu")
		(net "M_A_CPU0_SA_DQS_DN<3>")
	)
	(segment
		(start 311.01157 -284.709108)
		(end 309.9943 -284.287722)
		(width 0.20066)
		(layer "F.Cu")
		(net "M_A_CPU0_SA_DQS_DN<3>")
	)
	(segment
		(start 332.906116 -267.219938)
		(end 332.750668 -267.487654)
		(width 0.088646)
		(layer "F.Cu")
		(net "M_A_CPU0_SA_DQS_DN<3>")
	)
	(segment
		(start 306.644294 -284.441646)
		(end 306.833016 -284.441646)
		(width 0.20066)
		(layer "F.Cu")
		(net "M_A_CPU0_SA_DQS_DN<3>")
	)
	(segment
		(start 301.891954 -284.016704)
		(end 302.153066 -284.277816)
		(width 0.20066)
		(layer "F.Cu")
		(net "M_A_CPU0_SA_DQS_DN<3>")
	)
	(segment
		(start 308.079394 -284.277816)
		(end 308.340506 -284.016704)
		(width 0.20066)
		(layer "F.Cu")
		(net "M_A_CPU0_SA_DQS_DN<3>")
	)
	(segment
		(start 309.381398 -284.016704)
		(end 308.887114 -284.016704)
		(width 0.20066)
		(layer "F.Cu")
		(net "M_A_CPU0_SA_DQS_DN<3>")
	)
	(segment
		(start 318.652906 -284.77972)
		(end 317.951358 -284.919166)
		(width 0.20066)
		(layer "F.Cu")
		(net "M_A_CPU0_SA_DQS_DN<3>")
	)
	(segment
		(start 320.64452 -283.983176)
		(end 320.144902 -284.482794)
		(width 0.20066)
		(layer "F.Cu")
		(net "M_A_CPU0_SA_DQS_DN<3>")
	)
	(segment
		(start 319.341246 -284.51556)
		(end 318.750696 -284.633162)
		(width 0.20066)
		(layer "F.Cu")
		(net "M_A_CPU0_SA_DQS_DN<3>")
	)
	(segment
		(start 332.271878 -267.826998)
		(end 332.271878 -267.966952)
		(width 0.088646)
		(layer "F.Cu")
		(net "M_A_CPU0_SA_DQS_DN<3>")
	)
	(segment
		(start 332.591664 -267.647166)
		(end 332.45171 -267.647166)
		(width 0.088646)
		(layer "F.Cu")
		(net "M_A_CPU0_SA_DQS_DN<3>")
	)
	(segment
		(start 323.62521 -280.143458)
		(end 323.066918 -281.612594)
		(width 0.1524)
		(layer "F.Cu")
		(net "M_A_CPU0_SA_DQS_DN<3>")
	)
	(segment
		(start 304.319178 -284.430978)
		(end 304.31994 -284.430978)
		(width 0.1016)
		(layer "F.Cu")
		(net "M_A_CPU0_SA_DQS_DN<3>")
	)
	(segment
		(start 309.652924 -284.287722)
		(end 309.381652 -284.01645)
		(width 0.20066)
		(layer "F.Cu")
		(net "M_A_CPU0_SA_DQS_DN<3>")
	)
	(segment
		(start 331.758544 -268.480286)
		(end 331.481176 -268.595348)
		(width 0.088646)
		(layer "F.Cu")
		(net "M_A_CPU0_SA_DQS_DN<3>")
	)
	(segment
		(start 323.066918 -281.612594)
		(end 322.77812 -281.901392)
		(width 0.1524)
		(layer "F.Cu")
		(net "M_A_CPU0_SA_DQS_DN<3>")
	)
	(segment
		(start 314.728098 -284.733238)
		(end 314.728098 -284.52699)
		(width 0.20066)
		(layer "F.Cu")
		(net "M_A_CPU0_SA_DQS_DN<3>")
	)
	(segment
		(start 303.341786 -284.703012)
		(end 303.650396 -284.703012)
		(width 0.20066)
		(layer "F.Cu")
		(net "M_A_CPU0_SA_DQS_DN<3>")
	)
	(segment
		(start 314.625228 -284.42412)
		(end 314.17768 -284.42412)
		(width 0.20066)
		(layer "F.Cu")
		(net "M_A_CPU0_SA_DQS_DN<3>")
	)
	(segment
		(start 322.097908 -282.353766)
		(end 321.67195 -282.779724)
		(width 0.20066)
		(layer "F.Cu")
		(net "M_A_CPU0_SA_DQS_DN<3>")
	)
	(segment
		(start 320.64452 -283.807154)
		(end 320.64452 -283.983176)
		(width 0.20066)
		(layer "F.Cu")
		(net "M_A_CPU0_SA_DQS_DN<3>")
	)
	(segment
		(start 311.195466 -284.709108)
		(end 311.01157 -284.709108)
		(width 0.20066)
		(layer "F.Cu")
		(net "M_A_CPU0_SA_DQS_DN<3>")
	)
	(segment
		(start 315.303154 -284.919166)
		(end 314.914026 -284.919166)
		(width 0.20066)
		(layer "F.Cu")
		(net "M_A_CPU0_SA_DQS_DN<3>")
	)
	(segment
		(start 332.69555 -267.54328)
		(end 332.591664 -267.647166)
		(width 0.088646)
		(layer "F.Cu")
		(net "M_A_CPU0_SA_DQS_DN<3>")
	)
	(segment
		(start 331.481176 -268.595348)
		(end 330.92644 -269.150338)
		(width 0.088646)
		(layer "F.Cu")
		(net "M_A_CPU0_SA_DQS_DN<3>")
	)
	(segment
		(start 331.793342 -268.445488)
		(end 331.758544 -268.480286)
		(width 0.088646)
		(layer "F.Cu")
		(net "M_A_CPU0_SA_DQS_DN<3>")
	)
	(segment
		(start 322.726304 -281.901392)
		(end 322.69938 -281.928316)
		(width 0.1524)
		(layer "F.Cu")
		(net "M_A_CPU0_SA_DQS_DN<3>")
	)
	(segment
		(start 322.77812 -281.901392)
		(end 322.726304 -281.901392)
		(width 0.1524)
		(layer "F.Cu")
		(net "M_A_CPU0_SA_DQS_DN<3>")
	)
	(segment
		(start 316.029594 -284.794706)
		(end 315.427614 -284.794706)
		(width 0.20066)
		(layer "F.Cu")
		(net "M_A_CPU0_SA_DQS_DN<3>")
	)
	(segment
		(start 307.781452 -284.277816)
		(end 308.079394 -284.277816)
		(width 0.20066)
		(layer "F.Cu")
		(net "M_A_CPU0_SA_DQS_DN<3>")
	)
	(segment
		(start 332.69555 -267.542772)
		(end 332.69555 -267.54328)
		(width 0.088646)
		(layer "F.Cu")
		(net "M_A_CPU0_SA_DQS_DN<3>")
	)
	(segment
		(start 319.48755 -284.61335)
		(end 319.341246 -284.51556)
		(width 0.20066)
		(layer "F.Cu")
		(net "M_A_CPU0_SA_DQS_DN<3>")
	)
	(segment
		(start 322.69938 -281.928316)
		(end 322.27393 -282.353766)
		(width 0.20066)
		(layer "F.Cu")
		(net "M_A_CPU0_SA_DQS_DN<3>")
	)
	(segment
		(start 301.343314 -284.016704)
		(end 301.891954 -284.016704)
		(width 0.20066)
		(layer "F.Cu")
		(net "M_A_CPU0_SA_DQS_DN<3>")
	)
	(segment
		(start 311.89168 -284.424882)
		(end 311.479692 -284.424882)
		(width 0.20066)
		(layer "F.Cu")
		(net "M_A_CPU0_SA_DQS_DN<3>")
	)
	(segment
		(start 304.31994 -284.430978)
		(end 304.330608 -284.441646)
		(width 0.1016)
		(layer "F.Cu")
		(net "M_A_CPU0_SA_DQS_DN<3>")
	)
	(segment
		(start 307.094382 -284.703012)
		(end 307.356256 -284.703012)
		(width 0.20066)
		(layer "F.Cu")
		(net "M_A_CPU0_SA_DQS_DN<3>")
	)
	(segment
		(start 303.92243 -293.780972)
		(end 304.319178 -293.780972)
		(width 0.20066)
		(layer "F.Cu")
		(net "M_A_CPU0_SA_DQS_DN<2>")
	)
	(segment
		(start 307.356256 -294.053006)
		(end 307.781452 -293.62781)
		(width 0.20066)
		(layer "F.Cu")
		(net "M_A_CPU0_SA_DQS_DN<2>")
	)
	(segment
		(start 318.988948 -294.313864)
		(end 318.864488 -294.189404)
		(width 0.20066)
		(layer "F.Cu")
		(net "M_A_CPU0_SA_DQS_DN<2>")
	)
	(segment
		(start 333.026766 -272.747232)
		(end 332.77683 -272.997168)
		(width 0.088646)
		(layer "F.Cu")
		(net "M_A_CPU0_SA_DQS_DN<2>")
	)
	(segment
		(start 303.650396 -294.053006)
		(end 303.92243 -293.780972)
		(width 0.20066)
		(layer "F.Cu")
		(net "M_A_CPU0_SA_DQS_DN<2>")
	)
	(segment
		(start 328.06386 -278.176736)
		(end 327.37298 -281.63139)
		(width 0.1524)
		(layer "F.Cu")
		(net "M_A_CPU0_SA_DQS_DN<2>")
	)
	(segment
		(start 323.14769 -294.036496)
		(end 322.477892 -294.313864)
		(width 0.20066)
		(layer "F.Cu")
		(net "M_A_CPU0_SA_DQS_DN<2>")
	)
	(segment
		(start 316.685168 -294.313864)
		(end 316.083188 -294.313864)
		(width 0.20066)
		(layer "F.Cu")
		(net "M_A_CPU0_SA_DQS_DN<2>")
	)
	(segment
		(start 332.363826 -273.100038)
		(end 332.200504 -273.263614)
		(width 0.088646)
		(layer "F.Cu")
		(net "M_A_CPU0_SA_DQS_DN<2>")
	)
	(segment
		(start 314.630308 -294.313864)
		(end 314.535312 -294.218868)
		(width 0.20066)
		(layer "F.Cu")
		(net "M_A_CPU0_SA_DQS_DN<2>")
	)
	(segment
		(start 304.319178 -293.780972)
		(end 304.31994 -293.780972)
		(width 0.1016)
		(layer "F.Cu")
		(net "M_A_CPU0_SA_DQS_DN<2>")
	)
	(segment
		(start 314.17768 -293.79164)
		(end 312.097928 -293.79164)
		(width 0.1016)
		(layer "F.Cu")
		(net "M_A_CPU0_SA_DQS_DN<2>")
	)
	(segment
		(start 311.48528 -293.82847)
		(end 311.48528 -294.035988)
		(width 0.20066)
		(layer "F.Cu")
		(net "M_A_CPU0_SA_DQS_DN<2>")
	)
	(segment
		(start 302.70577 -293.62781)
		(end 303.341786 -294.053006)
		(width 0.20066)
		(layer "F.Cu")
		(net "M_A_CPU0_SA_DQS_DN<2>")
	)
	(segment
		(start 306.977034 -293.782242)
		(end 307.247798 -294.053006)
		(width 0.20066)
		(layer "F.Cu")
		(net "M_A_CPU0_SA_DQS_DN<2>")
	)
	(segment
		(start 318.864488 -294.189404)
		(end 318.262508 -294.189404)
		(width 0.20066)
		(layer "F.Cu")
		(net "M_A_CPU0_SA_DQS_DN<2>")
	)
	(segment
		(start 320.359786 -294.189404)
		(end 319.757806 -294.189404)
		(width 0.20066)
		(layer "F.Cu")
		(net "M_A_CPU0_SA_DQS_DN<2>")
	)
	(segment
		(start 323.215 -293.873936)
		(end 323.14769 -294.036496)
		(width 0.20066)
		(layer "F.Cu")
		(net "M_A_CPU0_SA_DQS_DN<2>")
	)
	(segment
		(start 321.937126 -294.313864)
		(end 321.812666 -294.189404)
		(width 0.20066)
		(layer "F.Cu")
		(net "M_A_CPU0_SA_DQS_DN<2>")
	)
	(segment
		(start 319.757806 -294.189404)
		(end 319.633346 -294.313864)
		(width 0.20066)
		(layer "F.Cu")
		(net "M_A_CPU0_SA_DQS_DN<2>")
	)
	(segment
		(start 302.153066 -293.62781)
		(end 302.70577 -293.62781)
		(width 0.20066)
		(layer "F.Cu")
		(net "M_A_CPU0_SA_DQS_DN<2>")
	)
	(segment
		(start 327.37298 -290.837366)
		(end 327.206864 -291.003482)
		(width 0.1524)
		(layer "F.Cu")
		(net "M_A_CPU0_SA_DQS_DN<2>")
	)
	(segment
		(start 321.210686 -294.189404)
		(end 321.086226 -294.313864)
		(width 0.20066)
		(layer "F.Cu")
		(net "M_A_CPU0_SA_DQS_DN<2>")
	)
	(segment
		(start 311.08904 -294.117014)
		(end 309.882794 -293.617396)
		(width 0.20066)
		(layer "F.Cu")
		(net "M_A_CPU0_SA_DQS_DN<2>")
	)
	(segment
		(start 309.632604 -293.617396)
		(end 309.381652 -293.366444)
		(width 0.20066)
		(layer "F.Cu")
		(net "M_A_CPU0_SA_DQS_DN<2>")
	)
	(segment
		(start 332.612238 -272.997168)
		(end 332.363826 -273.100038)
		(width 0.088646)
		(layer "F.Cu")
		(net "M_A_CPU0_SA_DQS_DN<2>")
	)
	(segment
		(start 323.934074 -293.710614)
		(end 323.771514 -293.643304)
		(width 0.20066)
		(layer "F.Cu")
		(net "M_A_CPU0_SA_DQS_DN<2>")
	)
	(segment
		(start 307.247798 -294.053006)
		(end 307.356256 -294.053006)
		(width 0.20066)
		(layer "F.Cu")
		(net "M_A_CPU0_SA_DQS_DN<2>")
	)
	(segment
		(start 304.330608 -293.79164)
		(end 306.634896 -293.79164)
		(width 0.1016)
		(layer "F.Cu")
		(net "M_A_CPU0_SA_DQS_DN<2>")
	)
	(segment
		(start 304.31994 -293.780972)
		(end 304.330608 -293.79164)
		(width 0.1016)
		(layer "F.Cu")
		(net "M_A_CPU0_SA_DQS_DN<2>")
	)
	(segment
		(start 332.77683 -272.997168)
		(end 332.612238 -272.997168)
		(width 0.088646)
		(layer "F.Cu")
		(net "M_A_CPU0_SA_DQS_DN<2>")
	)
	(segment
		(start 332.200504 -273.263614)
		(end 331.793088 -273.87296)
		(width 0.088646)
		(layer "F.Cu")
		(net "M_A_CPU0_SA_DQS_DN<2>")
	)
	(segment
		(start 308.340506 -293.366698)
		(end 308.887114 -293.366698)
		(width 0.20066)
		(layer "F.Cu")
		(net "M_A_CPU0_SA_DQS_DN<2>")
	)
	(segment
		(start 333.205836 -272.747232)
		(end 333.026766 -272.747232)
		(width 0.088646)
		(layer "F.Cu")
		(net "M_A_CPU0_SA_DQS_DN<2>")
	)
	(segment
		(start 314.299092 -293.79164)
		(end 314.17768 -293.79164)
		(width 0.20066)
		(layer "F.Cu")
		(net "M_A_CPU0_SA_DQS_DN<2>")
	)
	(segment
		(start 301.891954 -293.366698)
		(end 302.153066 -293.62781)
		(width 0.20066)
		(layer "F.Cu")
		(net "M_A_CPU0_SA_DQS_DN<2>")
	)
	(segment
		(start 331.400404 -274.266152)
		(end 331.38491 -274.281646)
		(width 0.088646)
		(layer "F.Cu")
		(net "M_A_CPU0_SA_DQS_DN<2>")
	)
	(segment
		(start 311.89168 -293.756842)
		(end 311.556908 -293.756842)
		(width 0.20066)
		(layer "F.Cu")
		(net "M_A_CPU0_SA_DQS_DN<2>")
	)
	(segment
		(start 326.100694 -292.057836)
		(end 325.675244 -292.483286)
		(width 0.20066)
		(layer "F.Cu")
		(net "M_A_CPU0_SA_DQS_DN<2>")
	)
	(segment
		(start 311.556908 -293.756842)
		(end 311.48528 -293.82847)
		(width 0.20066)
		(layer "F.Cu")
		(net "M_A_CPU0_SA_DQS_DN<2>")
	)
	(segment
		(start 309.381398 -293.366698)
		(end 308.887114 -293.366698)
		(width 0.20066)
		(layer "F.Cu")
		(net "M_A_CPU0_SA_DQS_DN<2>")
	)
	(segment
		(start 306.644294 -293.782242)
		(end 306.977034 -293.782242)
		(width 0.20066)
		(layer "F.Cu")
		(net "M_A_CPU0_SA_DQS_DN<2>")
	)
	(segment
		(start 327.128124 -291.030406)
		(end 326.702674 -291.455856)
		(width 0.20066)
		(layer "F.Cu")
		(net "M_A_CPU0_SA_DQS_DN<2>")
	)
	(segment
		(start 314.535312 -294.218868)
		(end 314.535312 -294.02786)
		(width 0.20066)
		(layer "F.Cu")
		(net "M_A_CPU0_SA_DQS_DN<2>")
	)
	(segment
		(start 318.138048 -294.313864)
		(end 317.536068 -294.313864)
		(width 0.20066)
		(layer "F.Cu")
		(net "M_A_CPU0_SA_DQS_DN<2>")
	)
	(segment
		(start 317.411608 -294.189404)
		(end 316.809628 -294.189404)
		(width 0.20066)
		(layer "F.Cu")
		(net "M_A_CPU0_SA_DQS_DN<2>")
	)
	(segment
		(start 326.100694 -291.881814)
		(end 326.100694 -292.057836)
		(width 0.20066)
		(layer "F.Cu")
		(net "M_A_CPU0_SA_DQS_DN<2>")
	)
	(segment
		(start 311.48528 -294.035988)
		(end 311.404254 -294.117014)
		(width 0.20066)
		(layer "F.Cu")
		(net "M_A_CPU0_SA_DQS_DN<2>")
	)
	(segment
		(start 324.81139 -293.347394)
		(end 323.934074 -293.710614)
		(width 0.20066)
		(layer "F.Cu")
		(net "M_A_CPU0_SA_DQS_DN<2>")
	)
	(segment
		(start 317.536068 -294.313864)
		(end 317.411608 -294.189404)
		(width 0.20066)
		(layer "F.Cu")
		(net "M_A_CPU0_SA_DQS_DN<2>")
	)
	(segment
		(start 306.634896 -293.79164)
		(end 306.644294 -293.782242)
		(width 0.1016)
		(layer "F.Cu")
		(net "M_A_CPU0_SA_DQS_DN<2>")
	)
	(segment
		(start 328.72172 -276.944836)
		(end 328.06386 -278.176736)
		(width 0.1524)
		(layer "F.Cu")
		(net "M_A_CPU0_SA_DQS_DN<2>")
	)
	(segment
		(start 303.341786 -294.053006)
		(end 303.650396 -294.053006)
		(width 0.20066)
		(layer "F.Cu")
		(net "M_A_CPU0_SA_DQS_DN<2>")
	)
	(segment
		(start 331.793088 -273.87296)
		(end 331.586078 -274.125182)
		(width 0.088646)
		(layer "F.Cu")
		(net "M_A_CPU0_SA_DQS_DN<2>")
	)
	(segment
		(start 327.37298 -281.63139)
		(end 327.37298 -290.837366)
		(width 0.1524)
		(layer "F.Cu")
		(net "M_A_CPU0_SA_DQS_DN<2>")
	)
	(segment
		(start 325.073264 -293.08552)
		(end 324.81139 -293.347394)
		(width 0.20066)
		(layer "F.Cu")
		(net "M_A_CPU0_SA_DQS_DN<2>")
	)
	(segment
		(start 322.477892 -294.313864)
		(end 321.937126 -294.313864)
		(width 0.20066)
		(layer "F.Cu")
		(net "M_A_CPU0_SA_DQS_DN<2>")
	)
	(segment
		(start 316.083188 -294.313864)
		(end 315.958728 -294.189404)
		(width 0.20066)
		(layer "F.Cu")
		(net "M_A_CPU0_SA_DQS_DN<2>")
	)
	(segment
		(start 312.097928 -293.79164)
		(end 311.947814 -293.756842)
		(width 0.1016)
		(layer "F.Cu")
		(net "M_A_CPU0_SA_DQS_DN<2>")
	)
	(segment
		(start 323.771514 -293.643304)
		(end 323.215 -293.873936)
		(width 0.20066)
		(layer "F.Cu")
		(net "M_A_CPU0_SA_DQS_DN<2>")
	)
	(segment
		(start 333.375762 -272.917158)
		(end 333.205836 -272.747232)
		(width 0.088646)
		(layer "F.Cu")
		(net "M_A_CPU0_SA_DQS_DN<2>")
	)
	(segment
		(start 315.958728 -294.189404)
		(end 315.356748 -294.189404)
		(width 0.20066)
		(layer "F.Cu")
		(net "M_A_CPU0_SA_DQS_DN<2>")
	)
	(segment
		(start 315.232288 -294.313864)
		(end 314.630308 -294.313864)
		(width 0.20066)
		(layer "F.Cu")
		(net "M_A_CPU0_SA_DQS_DN<2>")
	)
	(segment
		(start 309.381652 -293.366444)
		(end 309.381398 -293.366698)
		(width 0.20066)
		(layer "F.Cu")
		(net "M_A_CPU0_SA_DQS_DN<2>")
	)
	(segment
		(start 307.781452 -293.62781)
		(end 308.079394 -293.62781)
		(width 0.20066)
		(layer "F.Cu")
		(net "M_A_CPU0_SA_DQS_DN<2>")
	)
	(segment
		(start 321.086226 -294.313864)
		(end 320.484246 -294.313864)
		(width 0.20066)
		(layer "F.Cu")
		(net "M_A_CPU0_SA_DQS_DN<2>")
	)
	(segment
		(start 331.38491 -274.281646)
		(end 328.72172 -276.944836)
		(width 0.1524)
		(layer "F.Cu")
		(net "M_A_CPU0_SA_DQS_DN<2>")
	)
	(segment
		(start 325.675244 -292.483286)
		(end 325.499222 -292.483286)
		(width 0.20066)
		(layer "F.Cu")
		(net "M_A_CPU0_SA_DQS_DN<2>")
	)
	(segment
		(start 327.155048 -291.003482)
		(end 327.128124 -291.030406)
		(width 0.1524)
		(layer "F.Cu")
		(net "M_A_CPU0_SA_DQS_DN<2>")
	)
	(segment
		(start 311.947814 -293.756842)
		(end 311.89168 -293.756842)
		(width 0.1016)
		(layer "F.Cu")
		(net "M_A_CPU0_SA_DQS_DN<2>")
	)
	(segment
		(start 325.073264 -292.909244)
		(end 325.073264 -293.08552)
		(width 0.20066)
		(layer "F.Cu")
		(net "M_A_CPU0_SA_DQS_DN<2>")
	)
	(segment
		(start 325.499222 -292.483286)
		(end 325.073264 -292.909244)
		(width 0.20066)
		(layer "F.Cu")
		(net "M_A_CPU0_SA_DQS_DN<2>")
	)
	(segment
		(start 331.586078 -274.125182)
		(end 331.445108 -274.266152)
		(width 0.088646)
		(layer "F.Cu")
		(net "M_A_CPU0_SA_DQS_DN<2>")
	)
	(segment
		(start 318.262508 -294.189404)
		(end 318.138048 -294.313864)
		(width 0.20066)
		(layer "F.Cu")
		(net "M_A_CPU0_SA_DQS_DN<2>")
	)
	(segment
		(start 315.356748 -294.189404)
		(end 315.232288 -294.313864)
		(width 0.20066)
		(layer "F.Cu")
		(net "M_A_CPU0_SA_DQS_DN<2>")
	)
	(segment
		(start 308.079394 -293.62781)
		(end 308.340506 -293.366698)
		(width 0.20066)
		(layer "F.Cu")
		(net "M_A_CPU0_SA_DQS_DN<2>")
	)
	(segment
		(start 326.526652 -291.455856)
		(end 326.100694 -291.881814)
		(width 0.20066)
		(layer "F.Cu")
		(net "M_A_CPU0_SA_DQS_DN<2>")
	)
	(segment
		(start 301.343314 -293.366698)
		(end 301.891954 -293.366698)
		(width 0.20066)
		(layer "F.Cu")
		(net "M_A_CPU0_SA_DQS_DN<2>")
	)
	(segment
		(start 311.404254 -294.117014)
		(end 311.08904 -294.117014)
		(width 0.20066)
		(layer "F.Cu")
		(net "M_A_CPU0_SA_DQS_DN<2>")
	)
	(segment
		(start 309.882794 -293.617396)
		(end 309.632604 -293.617396)
		(width 0.20066)
		(layer "F.Cu")
		(net "M_A_CPU0_SA_DQS_DN<2>")
	)
	(segment
		(start 320.484246 -294.313864)
		(end 320.359786 -294.189404)
		(width 0.20066)
		(layer "F.Cu")
		(net "M_A_CPU0_SA_DQS_DN<2>")
	)
	(segment
		(start 331.445108 -274.266152)
		(end 331.400404 -274.266152)
		(width 0.088646)
		(layer "F.Cu")
		(net "M_A_CPU0_SA_DQS_DN<2>")
	)
	(segment
		(start 314.535312 -294.02786)
		(end 314.299092 -293.79164)
		(width 0.20066)
		(layer "F.Cu")
		(net "M_A_CPU0_SA_DQS_DN<2>")
	)
	(segment
		(start 326.702674 -291.455856)
		(end 326.526652 -291.455856)
		(width 0.20066)
		(layer "F.Cu")
		(net "M_A_CPU0_SA_DQS_DN<2>")
	)
	(segment
		(start 319.633346 -294.313864)
		(end 318.988948 -294.313864)
		(width 0.20066)
		(layer "F.Cu")
		(net "M_A_CPU0_SA_DQS_DN<2>")
	)
	(segment
		(start 316.809628 -294.189404)
		(end 316.685168 -294.313864)
		(width 0.20066)
		(layer "F.Cu")
		(net "M_A_CPU0_SA_DQS_DN<2>")
	)
	(segment
		(start 327.206864 -291.003482)
		(end 327.155048 -291.003482)
		(width 0.1524)
		(layer "F.Cu")
		(net "M_A_CPU0_SA_DQS_DN<2>")
	)
	(segment
		(start 321.812666 -294.189404)
		(end 321.210686 -294.189404)
		(width 0.20066)
		(layer "F.Cu")
		(net "M_A_CPU0_SA_DQS_DN<2>")
	)
	(segment
		(start 304.330608 -303.141634)
		(end 304.31994 -303.130966)
		(width 0.101854)
		(layer "F.Cu")
		(net "M_A_CPU0_SA_DQS_DN<1>")
	)
	(segment
		(start 307.67274 -302.977804)
		(end 307.247544 -303.403)
		(width 0.20066)
		(layer "F.Cu")
		(net "M_A_CPU0_SA_DQS_DN<1>")
	)
	(segment
		(start 306.799488 -303.141634)
		(end 306.644294 -303.141634)
		(width 0.20066)
		(layer "F.Cu")
		(net "M_A_CPU0_SA_DQS_DN<1>")
	)
	(segment
		(start 309.992014 -302.716692)
		(end 308.887114 -302.716692)
		(width 0.20066)
		(layer "F.Cu")
		(net "M_A_CPU0_SA_DQS_DN<1>")
	)
	(segment
		(start 304.114962 -303.130966)
		(end 303.842928 -303.403)
		(width 0.20066)
		(layer "F.Cu")
		(net "M_A_CPU0_SA_DQS_DN<1>")
	)
	(segment
		(start 302.666908 -302.977804)
		(end 302.153066 -302.977804)
		(width 0.20066)
		(layer "F.Cu")
		(net "M_A_CPU0_SA_DQS_DN<1>")
	)
	(segment
		(start 306.644294 -303.141634)
		(end 304.330608 -303.141634)
		(width 0.1016)
		(layer "F.Cu")
		(net "M_A_CPU0_SA_DQS_DN<1>")
	)
	(segment
		(start 302.153066 -302.977804)
		(end 301.891954 -302.716692)
		(width 0.20066)
		(layer "F.Cu")
		(net "M_A_CPU0_SA_DQS_DN<1>")
	)
	(segment
		(start 308.887114 -302.716692)
		(end 308.340506 -302.716692)
		(width 0.20066)
		(layer "F.Cu")
		(net "M_A_CPU0_SA_DQS_DN<1>")
	)
	(segment
		(start 308.340506 -302.716692)
		(end 308.079394 -302.977804)
		(width 0.20066)
		(layer "F.Cu")
		(net "M_A_CPU0_SA_DQS_DN<1>")
	)
	(segment
		(start 307.060854 -303.403)
		(end 306.799488 -303.141634)
		(width 0.20066)
		(layer "F.Cu")
		(net "M_A_CPU0_SA_DQS_DN<1>")
	)
	(segment
		(start 304.31994 -303.130966)
		(end 304.319178 -303.130966)
		(width 0.101854)
		(layer "F.Cu")
		(net "M_A_CPU0_SA_DQS_DN<1>")
	)
	(segment
		(start 303.842928 -303.403)
		(end 303.302924 -303.403)
		(width 0.20066)
		(layer "F.Cu")
		(net "M_A_CPU0_SA_DQS_DN<1>")
	)
	(segment
		(start 301.891954 -302.716692)
		(end 301.343314 -302.716692)
		(width 0.20066)
		(layer "F.Cu")
		(net "M_A_CPU0_SA_DQS_DN<1>")
	)
	(segment
		(start 304.319178 -303.130966)
		(end 304.114962 -303.130966)
		(width 0.20066)
		(layer "F.Cu")
		(net "M_A_CPU0_SA_DQS_DN<1>")
	)
	(segment
		(start 307.247544 -303.403)
		(end 307.060854 -303.403)
		(width 0.20066)
		(layer "F.Cu")
		(net "M_A_CPU0_SA_DQS_DN<1>")
	)
	(segment
		(start 303.302924 -303.403)
		(end 302.666908 -302.977804)
		(width 0.20066)
		(layer "F.Cu")
		(net "M_A_CPU0_SA_DQS_DN<1>")
	)
	(segment
		(start 308.079394 -302.977804)
		(end 307.67274 -302.977804)
		(width 0.20066)
		(layer "F.Cu")
		(net "M_A_CPU0_SA_DQS_DN<1>")
	)
	(segment
		(start 336.195162 -269.66164)
		(end 336.195162 -270.19758)
		(width 0.20066)
		(layer "F.Cu")
		(net "M_A_CPU0_SA_DQS_DN<1>")
	)
	(segment
		(start 332.824836 -271.146524)
		(end 332.564486 -271.406874)
		(width 0.18288)
		(layer "In2.Cu")
		(net "M_A_CPU0_SA_DQS_DN<1>")
	)
	(segment
		(start 313.891168 -303.141634)
		(end 313.637422 -303.39538)
		(width 0.18288)
		(layer "In2.Cu")
		(net "M_A_CPU0_SA_DQS_DN<1>")
	)
	(segment
		(start 312.272934 -303.132744)
		(end 312.07329 -302.9331)
		(width 0.16002)
		(layer "In2.Cu")
		(net "M_A_CPU0_SA_DQS_DN<1>")
	)
	(segment
		(start 319.274698 -291.017706)
		(end 319.06464 -291.524436)
		(width 0.18288)
		(layer "In2.Cu")
		(net "M_A_CPU0_SA_DQS_DN<1>")
	)
	(segment
		(start 317.727838 -294.74922)
		(end 316.558422 -297.570652)
		(width 0.18288)
		(layer "In2.Cu")
		(net "M_A_CPU0_SA_DQS_DN<1>")
	)
	(segment
		(start 312.045096 -302.88865)
		(end 311.793636 -302.63719)
		(width 0.18288)
		(layer "In2.Cu")
		(net "M_A_CPU0_SA_DQS_DN<1>")
	)
	(segment
		(start 333.076042 -270.980154)
		(end 332.909672 -271.146524)
		(width 0.088646)
		(layer "In2.Cu")
		(net "M_A_CPU0_SA_DQS_DN<1>")
	)
	(segment
		(start 310.279796 -303.004474)
		(end 309.992014 -302.716692)
		(width 0.18288)
		(layer "In2.Cu")
		(net "M_A_CPU0_SA_DQS_DN<1>")
	)
	(segment
		(start 325.005954 -280.986484)
		(end 324.023736 -283.355796)
		(width 0.18288)
		(layer "In2.Cu")
		(net "M_A_CPU0_SA_DQS_DN<1>")
	)
	(segment
		(start 324.023736 -283.355796)
		(end 321.337178 -286.042354)
		(width 0.18288)
		(layer "In2.Cu")
		(net "M_A_CPU0_SA_DQS_DN<1>")
	)
	(segment
		(start 329.151234 -276.625304)
		(end 325.157846 -280.618692)
		(width 0.18288)
		(layer "In2.Cu")
		(net "M_A_CPU0_SA_DQS_DN<1>")
	)
	(segment
		(start 330.42479 -273.546824)
		(end 329.151234 -276.625304)
		(width 0.18288)
		(layer "In2.Cu")
		(net "M_A_CPU0_SA_DQS_DN<1>")
	)
	(segment
		(start 318.54902 -292.768274)
		(end 318.386206 -292.835584)
		(width 0.18288)
		(layer "In2.Cu")
		(net "M_A_CPU0_SA_DQS_DN<1>")
	)
	(segment
		(start 312.483754 -303.327054)
		(end 312.317384 -303.160938)
		(width 0.18288)
		(layer "In2.Cu")
		(net "M_A_CPU0_SA_DQS_DN<1>")
	)
	(segment
		(start 336.195162 -270.19758)
		(end 335.979262 -270.41348)
		(width 0.088646)
		(layer "In2.Cu")
		(net "M_A_CPU0_SA_DQS_DN<1>")
	)
	(segment
		(start 318.176148 -293.342568)
		(end 318.243458 -293.505382)
		(width 0.18288)
		(layer "In2.Cu")
		(net "M_A_CPU0_SA_DQS_DN<1>")
	)
	(segment
		(start 325.157846 -280.618692)
		(end 325.094346 -280.771092)
		(width 0.18288)
		(layer "In2.Cu")
		(net "M_A_CPU0_SA_DQS_DN<1>")
	)
	(segment
		(start 316.558422 -300.301152)
		(end 315.654944 -302.481742)
		(width 0.18288)
		(layer "In2.Cu")
		(net "M_A_CPU0_SA_DQS_DN<1>")
	)
	(segment
		(start 316.558422 -297.570652)
		(end 316.558422 -297.95216)
		(width 0.18288)
		(layer "In2.Cu")
		(net "M_A_CPU0_SA_DQS_DN<1>")
	)
	(segment
		(start 321.337178 -286.042354)
		(end 321.12712 -286.549084)
		(width 0.18288)
		(layer "In2.Cu")
		(net "M_A_CPU0_SA_DQS_DN<1>")
	)
	(segment
		(start 334.38592 -270.611092)
		(end 334.017112 -270.980154)
		(width 0.088646)
		(layer "In2.Cu")
		(net "M_A_CPU0_SA_DQS_DN<1>")
	)
	(segment
		(start 318.0334 -294.012112)
		(end 317.870586 -294.079422)
		(width 0.18288)
		(layer "In2.Cu")
		(net "M_A_CPU0_SA_DQS_DN<1>")
	)
	(segment
		(start 318.243458 -293.505382)
		(end 318.0334 -294.012112)
		(width 0.18288)
		(layer "In2.Cu")
		(net "M_A_CPU0_SA_DQS_DN<1>")
	)
	(segment
		(start 319.933066 -289.10407)
		(end 319.723008 -289.611054)
		(width 0.18288)
		(layer "In2.Cu")
		(net "M_A_CPU0_SA_DQS_DN<1>")
	)
	(segment
		(start 320.448686 -287.860232)
		(end 320.238628 -288.367216)
		(width 0.18288)
		(layer "In2.Cu")
		(net "M_A_CPU0_SA_DQS_DN<1>")
	)
	(segment
		(start 317.660528 -294.586406)
		(end 317.727838 -294.74922)
		(width 0.18288)
		(layer "In2.Cu")
		(net "M_A_CPU0_SA_DQS_DN<1>")
	)
	(segment
		(start 312.07329 -302.9331)
		(end 312.07329 -302.916844)
		(width 0.16002)
		(layer "In2.Cu")
		(net "M_A_CPU0_SA_DQS_DN<1>")
	)
	(segment
		(start 320.6115 -287.792922)
		(end 320.448686 -287.860232)
		(width 0.18288)
		(layer "In2.Cu")
		(net "M_A_CPU0_SA_DQS_DN<1>")
	)
	(segment
		(start 314.542932 -303.409858)
		(end 314.274708 -303.141634)
		(width 0.18288)
		(layer "In2.Cu")
		(net "M_A_CPU0_SA_DQS_DN<1>")
	)
	(segment
		(start 335.979262 -270.41348)
		(end 335.631282 -270.41348)
		(width 0.088646)
		(layer "In2.Cu")
		(net "M_A_CPU0_SA_DQS_DN<1>")
	)
	(segment
		(start 318.386206 -292.835584)
		(end 318.176148 -293.342568)
		(width 0.18288)
		(layer "In2.Cu")
		(net "M_A_CPU0_SA_DQS_DN<1>")
	)
	(segment
		(start 319.207388 -290.854892)
		(end 319.274698 -291.017706)
		(width 0.18288)
		(layer "In2.Cu")
		(net "M_A_CPU0_SA_DQS_DN<1>")
	)
	(segment
		(start 320.754248 -287.123378)
		(end 320.821558 -287.286192)
		(width 0.18288)
		(layer "In2.Cu")
		(net "M_A_CPU0_SA_DQS_DN<1>")
	)
	(segment
		(start 312.317384 -303.160938)
		(end 312.28919 -303.132744)
		(width 0.16002)
		(layer "In2.Cu")
		(net "M_A_CPU0_SA_DQS_DN<1>")
	)
	(segment
		(start 320.305938 -288.53003)
		(end 320.09588 -289.03676)
		(width 0.18288)
		(layer "In2.Cu")
		(net "M_A_CPU0_SA_DQS_DN<1>")
	)
	(segment
		(start 319.58026 -290.280598)
		(end 319.417446 -290.347908)
		(width 0.18288)
		(layer "In2.Cu")
		(net "M_A_CPU0_SA_DQS_DN<1>")
	)
	(segment
		(start 325.094346 -280.771092)
		(end 325.094854 -280.771854)
		(width 0.18288)
		(layer "In2.Cu")
		(net "M_A_CPU0_SA_DQS_DN<1>")
	)
	(segment
		(start 316.558422 -299.29836)
		(end 316.433962 -299.42282)
		(width 0.18288)
		(layer "In2.Cu")
		(net "M_A_CPU0_SA_DQS_DN<1>")
	)
	(segment
		(start 332.909672 -271.146524)
		(end 332.824836 -271.146524)
		(width 0.088646)
		(layer "In2.Cu")
		(net "M_A_CPU0_SA_DQS_DN<1>")
	)
	(segment
		(start 320.09588 -289.03676)
		(end 319.933066 -289.10407)
		(width 0.18288)
		(layer "In2.Cu")
		(net "M_A_CPU0_SA_DQS_DN<1>")
	)
	(segment
		(start 316.433962 -298.62526)
		(end 316.558422 -298.74972)
		(width 0.18288)
		(layer "In2.Cu")
		(net "M_A_CPU0_SA_DQS_DN<1>")
	)
	(segment
		(start 312.648346 -303.39538)
		(end 312.483754 -303.327054)
		(width 0.18288)
		(layer "In2.Cu")
		(net "M_A_CPU0_SA_DQS_DN<1>")
	)
	(segment
		(start 316.433962 -299.42282)
		(end 316.433962 -299.97146)
		(width 0.18288)
		(layer "In2.Cu")
		(net "M_A_CPU0_SA_DQS_DN<1>")
	)
	(segment
		(start 320.964306 -286.616394)
		(end 320.754248 -287.123378)
		(width 0.18288)
		(layer "In2.Cu")
		(net "M_A_CPU0_SA_DQS_DN<1>")
	)
	(segment
		(start 316.558422 -298.74972)
		(end 316.558422 -299.29836)
		(width 0.18288)
		(layer "In2.Cu")
		(net "M_A_CPU0_SA_DQS_DN<1>")
	)
	(segment
		(start 319.417446 -290.347908)
		(end 319.207388 -290.854892)
		(width 0.18288)
		(layer "In2.Cu")
		(net "M_A_CPU0_SA_DQS_DN<1>")
	)
	(segment
		(start 315.654944 -302.481742)
		(end 314.727082 -303.409858)
		(width 0.18288)
		(layer "In2.Cu")
		(net "M_A_CPU0_SA_DQS_DN<1>")
	)
	(segment
		(start 312.07329 -302.916844)
		(end 312.045096 -302.88865)
		(width 0.16002)
		(layer "In2.Cu")
		(net "M_A_CPU0_SA_DQS_DN<1>")
	)
	(segment
		(start 316.558422 -297.95216)
		(end 316.433962 -298.07662)
		(width 0.18288)
		(layer "In2.Cu")
		(net "M_A_CPU0_SA_DQS_DN<1>")
	)
	(segment
		(start 325.094854 -280.771854)
		(end 325.005954 -280.986484)
		(width 0.18288)
		(layer "In2.Cu")
		(net "M_A_CPU0_SA_DQS_DN<1>")
	)
	(segment
		(start 314.727082 -303.409858)
		(end 314.542932 -303.409858)
		(width 0.18288)
		(layer "In2.Cu")
		(net "M_A_CPU0_SA_DQS_DN<1>")
	)
	(segment
		(start 321.12712 -286.549084)
		(end 320.964306 -286.616394)
		(width 0.18288)
		(layer "In2.Cu")
		(net "M_A_CPU0_SA_DQS_DN<1>")
	)
	(segment
		(start 318.691768 -292.09873)
		(end 318.759078 -292.261544)
		(width 0.18288)
		(layer "In2.Cu")
		(net "M_A_CPU0_SA_DQS_DN<1>")
	)
	(segment
		(start 318.759078 -292.261544)
		(end 318.54902 -292.768274)
		(width 0.18288)
		(layer "In2.Cu")
		(net "M_A_CPU0_SA_DQS_DN<1>")
	)
	(segment
		(start 320.238628 -288.367216)
		(end 320.305938 -288.53003)
		(width 0.18288)
		(layer "In2.Cu")
		(net "M_A_CPU0_SA_DQS_DN<1>")
	)
	(segment
		(start 319.790318 -289.773868)
		(end 319.58026 -290.280598)
		(width 0.18288)
		(layer "In2.Cu")
		(net "M_A_CPU0_SA_DQS_DN<1>")
	)
	(segment
		(start 310.889904 -302.63719)
		(end 310.52262 -303.004474)
		(width 0.18288)
		(layer "In2.Cu")
		(net "M_A_CPU0_SA_DQS_DN<1>")
	)
	(segment
		(start 313.637422 -303.39538)
		(end 312.648346 -303.39538)
		(width 0.18288)
		(layer "In2.Cu")
		(net "M_A_CPU0_SA_DQS_DN<1>")
	)
	(segment
		(start 311.793636 -302.63719)
		(end 310.889904 -302.63719)
		(width 0.18288)
		(layer "In2.Cu")
		(net "M_A_CPU0_SA_DQS_DN<1>")
	)
	(segment
		(start 312.28919 -303.132744)
		(end 312.272934 -303.132744)
		(width 0.16002)
		(layer "In2.Cu")
		(net "M_A_CPU0_SA_DQS_DN<1>")
	)
	(segment
		(start 319.06464 -291.524436)
		(end 318.901826 -291.591746)
		(width 0.18288)
		(layer "In2.Cu")
		(net "M_A_CPU0_SA_DQS_DN<1>")
	)
	(segment
		(start 334.017112 -270.980154)
		(end 333.076042 -270.980154)
		(width 0.088646)
		(layer "In2.Cu")
		(net "M_A_CPU0_SA_DQS_DN<1>")
	)
	(segment
		(start 318.901826 -291.591746)
		(end 318.691768 -292.09873)
		(width 0.18288)
		(layer "In2.Cu")
		(net "M_A_CPU0_SA_DQS_DN<1>")
	)
	(segment
		(start 317.870586 -294.079422)
		(end 317.660528 -294.586406)
		(width 0.18288)
		(layer "In2.Cu")
		(net "M_A_CPU0_SA_DQS_DN<1>")
	)
	(segment
		(start 320.821558 -287.286192)
		(end 320.6115 -287.792922)
		(width 0.18288)
		(layer "In2.Cu")
		(net "M_A_CPU0_SA_DQS_DN<1>")
	)
	(segment
		(start 332.564486 -271.406874)
		(end 330.42479 -273.546824)
		(width 0.18288)
		(layer "In2.Cu")
		(net "M_A_CPU0_SA_DQS_DN<1>")
	)
	(segment
		(start 316.558422 -300.09592)
		(end 316.558422 -300.301152)
		(width 0.18288)
		(layer "In2.Cu")
		(net "M_A_CPU0_SA_DQS_DN<1>")
	)
	(segment
		(start 316.433962 -298.07662)
		(end 316.433962 -298.62526)
		(width 0.18288)
		(layer "In2.Cu")
		(net "M_A_CPU0_SA_DQS_DN<1>")
	)
	(segment
		(start 314.274708 -303.141634)
		(end 313.891168 -303.141634)
		(width 0.18288)
		(layer "In2.Cu")
		(net "M_A_CPU0_SA_DQS_DN<1>")
	)
	(segment
		(start 319.723008 -289.611054)
		(end 319.790318 -289.773868)
		(width 0.18288)
		(layer "In2.Cu")
		(net "M_A_CPU0_SA_DQS_DN<1>")
	)
	(segment
		(start 316.433962 -299.97146)
		(end 316.558422 -300.09592)
		(width 0.18288)
		(layer "In2.Cu")
		(net "M_A_CPU0_SA_DQS_DN<1>")
	)
	(segment
		(start 335.631282 -270.41348)
		(end 335.443068 -270.522192)
		(width 0.088646)
		(layer "In2.Cu")
		(net "M_A_CPU0_SA_DQS_DN<1>")
	)
	(segment
		(start 335.06791 -270.522192)
		(end 335.067656 -270.522192)
		(width 0.088646)
		(layer "In2.Cu")
		(net "M_A_CPU0_SA_DQS_DN<1>")
	)
	(segment
		(start 310.52262 -303.004474)
		(end 310.279796 -303.004474)
		(width 0.18288)
		(layer "In2.Cu")
		(net "M_A_CPU0_SA_DQS_DN<1>")
	)
	(arc
		(start 335.443068 -270.522192)
		(mid 335.255506 -270.572428)
		(end 335.06791 -270.522192)
		(width 0.088646)
		(layer "In2.Cu")
		(net "M_A_CPU0_SA_DQS_DN<1>")
	)
	(arc
		(start 334.503522 -270.521938)
		(mid 334.441788 -270.562648)
		(end 334.38592 -270.611092)
		(width 0.088646)
		(layer "In2.Cu")
		(net "M_A_CPU0_SA_DQS_DN<1>")
	)
	(arc
		(start 335.067656 -270.522192)
		(mid 334.785635 -270.446636)
		(end 334.503522 -270.521938)
		(width 0.088646)
		(layer "In2.Cu")
		(net "M_A_CPU0_SA_DQS_DN<1>")
	)
	(segment
		(start 316.451996 -311.352946)
		(end 316.275974 -311.352946)
		(width 0.20066)
		(layer "F.Cu")
		(net "M_A_CPU0_SA_DQS_DN<0>")
	)
	(segment
		(start 330.856082 -297.762168)
		(end 330.53147 -298.08678)
		(width 0.1524)
		(layer "F.Cu")
		(net "M_A_CPU0_SA_DQS_DN<0>")
	)
	(segment
		(start 314.983876 -312.732674)
		(end 314.827666 -312.732674)
		(width 0.20066)
		(layer "F.Cu")
		(net "M_A_CPU0_SA_DQS_DN<0>")
	)
	(segment
		(start 304.330608 -312.491628)
		(end 306.634896 -312.491628)
		(width 0.1016)
		(layer "F.Cu")
		(net "M_A_CPU0_SA_DQS_DN<0>")
	)
	(segment
		(start 332.15834 -279.341834)
		(end 332.142846 -279.357328)
		(width 0.088646)
		(layer "F.Cu")
		(net "M_A_CPU0_SA_DQS_DN<0>")
	)
	(segment
		(start 315.134752 -312.67019)
		(end 314.983876 -312.732674)
		(width 0.20066)
		(layer "F.Cu")
		(net "M_A_CPU0_SA_DQS_DN<0>")
	)
	(segment
		(start 304.31994 -312.48096)
		(end 304.330608 -312.491628)
		(width 0.1016)
		(layer "F.Cu")
		(net "M_A_CPU0_SA_DQS_DN<0>")
	)
	(segment
		(start 308.079394 -312.327798)
		(end 308.340506 -312.066686)
		(width 0.20066)
		(layer "F.Cu")
		(net "M_A_CPU0_SA_DQS_DN<0>")
	)
	(segment
		(start 301.343314 -312.066686)
		(end 301.891954 -312.066686)
		(width 0.20066)
		(layer "F.Cu")
		(net "M_A_CPU0_SA_DQS_DN<0>")
	)
	(segment
		(start 309.381398 -312.066686)
		(end 308.887114 -312.066686)
		(width 0.20066)
		(layer "F.Cu")
		(net "M_A_CPU0_SA_DQS_DN<0>")
	)
	(segment
		(start 309.652924 -312.337704)
		(end 309.381652 -312.066432)
		(width 0.20066)
		(layer "F.Cu")
		(net "M_A_CPU0_SA_DQS_DN<0>")
	)
	(segment
		(start 324.417182 -304.148998)
		(end 320.170302 -307.63464)
		(width 0.20066)
		(layer "F.Cu")
		(net "M_A_CPU0_SA_DQS_DN<0>")
	)
	(segment
		(start 333.686658 -277.800562)
		(end 333.745586 -277.85949)
		(width 0.088646)
		(layer "F.Cu")
		(net "M_A_CPU0_SA_DQS_DN<0>")
	)
	(segment
		(start 331.829156 -279.671018)
		(end 331.28458 -282.393898)
		(width 0.1524)
		(layer "F.Cu")
		(net "M_A_CPU0_SA_DQS_DN<0>")
	)
	(segment
		(start 315.85027 -311.954672)
		(end 315.134752 -312.67019)
		(width 0.20066)
		(layer "F.Cu")
		(net "M_A_CPU0_SA_DQS_DN<0>")
	)
	(segment
		(start 314.827666 -312.732674)
		(end 314.578238 -312.483246)
		(width 0.20066)
		(layer "F.Cu")
		(net "M_A_CPU0_SA_DQS_DN<0>")
	)
	(segment
		(start 309.381652 -312.066432)
		(end 309.381398 -312.066686)
		(width 0.20066)
		(layer "F.Cu")
		(net "M_A_CPU0_SA_DQS_DN<0>")
	)
	(segment
		(start 311.983374 -312.485786)
		(end 311.94248 -312.485786)
		(width 0.1016)
		(layer "F.Cu")
		(net "M_A_CPU0_SA_DQS_DN<0>")
	)
	(segment
		(start 316.877446 -310.927496)
		(end 316.451996 -311.352946)
		(width 0.20066)
		(layer "F.Cu")
		(net "M_A_CPU0_SA_DQS_DN<0>")
	)
	(segment
		(start 332.203552 -279.341834)
		(end 332.15834 -279.341834)
		(width 0.088646)
		(layer "F.Cu")
		(net "M_A_CPU0_SA_DQS_DN<0>")
	)
	(segment
		(start 303.92243 -312.48096)
		(end 304.319178 -312.48096)
		(width 0.20066)
		(layer "F.Cu")
		(net "M_A_CPU0_SA_DQS_DN<0>")
	)
	(segment
		(start 316.275974 -311.352946)
		(end 315.85027 -311.77865)
		(width 0.20066)
		(layer "F.Cu")
		(net "M_A_CPU0_SA_DQS_DN<0>")
	)
	(segment
		(start 309.922418 -312.337704)
		(end 309.652924 -312.337704)
		(width 0.20066)
		(layer "F.Cu")
		(net "M_A_CPU0_SA_DQS_DN<0>")
	)
	(segment
		(start 306.634896 -312.491628)
		(end 306.644294 -312.48223)
		(width 0.1016)
		(layer "F.Cu")
		(net "M_A_CPU0_SA_DQS_DN<0>")
	)
	(segment
		(start 316.877446 -310.751474)
		(end 316.877446 -310.927496)
		(width 0.20066)
		(layer "F.Cu")
		(net "M_A_CPU0_SA_DQS_DN<0>")
	)
	(segment
		(start 331.28458 -296.159936)
		(end 331.070458 -297.236134)
		(width 0.1524)
		(layer "F.Cu")
		(net "M_A_CPU0_SA_DQS_DN<0>")
	)
	(segment
		(start 302.153066 -312.327798)
		(end 302.711104 -312.327798)
		(width 0.20066)
		(layer "F.Cu")
		(net "M_A_CPU0_SA_DQS_DN<0>")
	)
	(segment
		(start 307.247798 -312.752994)
		(end 307.356256 -312.752994)
		(width 0.20066)
		(layer "F.Cu")
		(net "M_A_CPU0_SA_DQS_DN<0>")
	)
	(segment
		(start 311.94248 -312.485786)
		(end 311.47385 -312.485786)
		(width 0.20066)
		(layer "F.Cu")
		(net "M_A_CPU0_SA_DQS_DN<0>")
	)
	(segment
		(start 333.375762 -277.800562)
		(end 333.686658 -277.800562)
		(width 0.088646)
		(layer "F.Cu")
		(net "M_A_CPU0_SA_DQS_DN<0>")
	)
	(segment
		(start 306.977034 -312.48223)
		(end 307.247798 -312.752994)
		(width 0.20066)
		(layer "F.Cu")
		(net "M_A_CPU0_SA_DQS_DN<0>")
	)
	(segment
		(start 303.650396 -312.752994)
		(end 303.92243 -312.48096)
		(width 0.20066)
		(layer "F.Cu")
		(net "M_A_CPU0_SA_DQS_DN<0>")
	)
	(segment
		(start 330.4794 -298.08678)
		(end 330.452476 -298.113704)
		(width 0.1524)
		(layer "F.Cu")
		(net "M_A_CPU0_SA_DQS_DN<0>")
	)
	(segment
		(start 301.891954 -312.066686)
		(end 302.153066 -312.327798)
		(width 0.20066)
		(layer "F.Cu")
		(net "M_A_CPU0_SA_DQS_DN<0>")
	)
	(segment
		(start 304.319178 -312.48096)
		(end 304.31994 -312.48096)
		(width 0.1016)
		(layer "F.Cu")
		(net "M_A_CPU0_SA_DQS_DN<0>")
	)
	(segment
		(start 317.303404 -310.325516)
		(end 316.877446 -310.751474)
		(width 0.20066)
		(layer "F.Cu")
		(net "M_A_CPU0_SA_DQS_DN<0>")
	)
	(segment
		(start 317.904876 -309.724044)
		(end 317.904876 -309.900066)
		(width 0.20066)
		(layer "F.Cu")
		(net "M_A_CPU0_SA_DQS_DN<0>")
	)
	(segment
		(start 317.479426 -310.325516)
		(end 317.303404 -310.325516)
		(width 0.20066)
		(layer "F.Cu")
		(net "M_A_CPU0_SA_DQS_DN<0>")
	)
	(segment
		(start 332.142846 -279.357328)
		(end 331.829156 -279.671018)
		(width 0.1524)
		(layer "F.Cu")
		(net "M_A_CPU0_SA_DQS_DN<0>")
	)
	(segment
		(start 330.452476 -298.113704)
		(end 324.417182 -304.148998)
		(width 0.20066)
		(layer "F.Cu")
		(net "M_A_CPU0_SA_DQS_DN<0>")
	)
	(segment
		(start 332.656434 -278.338788)
		(end 332.551024 -278.59482)
		(width 0.088646)
		(layer "F.Cu")
		(net "M_A_CPU0_SA_DQS_DN<0>")
	)
	(segment
		(start 302.711104 -312.327798)
		(end 303.34712 -312.752994)
		(width 0.20066)
		(layer "F.Cu")
		(net "M_A_CPU0_SA_DQS_DN<0>")
	)
	(segment
		(start 320.170302 -307.63464)
		(end 318.506856 -309.298086)
		(width 0.20066)
		(layer "F.Cu")
		(net "M_A_CPU0_SA_DQS_DN<0>")
	)
	(segment
		(start 303.34712 -312.752994)
		(end 303.650396 -312.752994)
		(width 0.20066)
		(layer "F.Cu")
		(net "M_A_CPU0_SA_DQS_DN<0>")
	)
	(segment
		(start 306.644294 -312.48223)
		(end 306.977034 -312.48223)
		(width 0.20066)
		(layer "F.Cu")
		(net "M_A_CPU0_SA_DQS_DN<0>")
	)
	(segment
		(start 311.989216 -312.491628)
		(end 311.983374 -312.485786)
		(width 0.1016)
		(layer "F.Cu")
		(net "M_A_CPU0_SA_DQS_DN<0>")
	)
	(segment
		(start 331.28458 -282.393898)
		(end 331.28458 -296.159936)
		(width 0.1524)
		(layer "F.Cu")
		(net "M_A_CPU0_SA_DQS_DN<0>")
	)
	(segment
		(start 314.12688 -312.483246)
		(end 314.111386 -312.483246)
		(width 0.1016)
		(layer "F.Cu")
		(net "M_A_CPU0_SA_DQS_DN<0>")
	)
	(segment
		(start 314.111386 -312.483246)
		(end 314.103004 -312.491628)
		(width 0.1016)
		(layer "F.Cu")
		(net "M_A_CPU0_SA_DQS_DN<0>")
	)
	(segment
		(start 314.578238 -312.483246)
		(end 314.12688 -312.483246)
		(width 0.20066)
		(layer "F.Cu")
		(net "M_A_CPU0_SA_DQS_DN<0>")
	)
	(segment
		(start 308.340506 -312.066686)
		(end 308.887114 -312.066686)
		(width 0.20066)
		(layer "F.Cu")
		(net "M_A_CPU0_SA_DQS_DN<0>")
	)
	(segment
		(start 332.551024 -278.59482)
		(end 332.551024 -278.864822)
		(width 0.088646)
		(layer "F.Cu")
		(net "M_A_CPU0_SA_DQS_DN<0>")
	)
	(segment
		(start 318.506856 -309.298086)
		(end 318.330834 -309.298086)
		(width 0.20066)
		(layer "F.Cu")
		(net "M_A_CPU0_SA_DQS_DN<0>")
	)
	(segment
		(start 333.498444 -278.137874)
		(end 332.857348 -278.137874)
		(width 0.088646)
		(layer "F.Cu")
		(net "M_A_CPU0_SA_DQS_DN<0>")
	)
	(segment
		(start 332.551024 -278.864822)
		(end 332.458568 -279.086818)
		(width 0.088646)
		(layer "F.Cu")
		(net "M_A_CPU0_SA_DQS_DN<0>")
	)
	(segment
		(start 311.19699 -312.762646)
		(end 310.948324 -312.762646)
		(width 0.20066)
		(layer "F.Cu")
		(net "M_A_CPU0_SA_DQS_DN<0>")
	)
	(segment
		(start 330.53147 -298.08678)
		(end 330.4794 -298.08678)
		(width 0.1524)
		(layer "F.Cu")
		(net "M_A_CPU0_SA_DQS_DN<0>")
	)
	(segment
		(start 332.458568 -279.086818)
		(end 332.203552 -279.341834)
		(width 0.088646)
		(layer "F.Cu")
		(net "M_A_CPU0_SA_DQS_DN<0>")
	)
	(segment
		(start 332.857348 -278.137874)
		(end 332.656434 -278.338788)
		(width 0.088646)
		(layer "F.Cu")
		(net "M_A_CPU0_SA_DQS_DN<0>")
	)
	(segment
		(start 317.904876 -309.900066)
		(end 317.479426 -310.325516)
		(width 0.20066)
		(layer "F.Cu")
		(net "M_A_CPU0_SA_DQS_DN<0>")
	)
	(segment
		(start 311.47385 -312.485786)
		(end 311.19699 -312.762646)
		(width 0.20066)
		(layer "F.Cu")
		(net "M_A_CPU0_SA_DQS_DN<0>")
	)
	(segment
		(start 331.070458 -297.236134)
		(end 331.06995 -297.237658)
		(width 0.1524)
		(layer "F.Cu")
		(net "M_A_CPU0_SA_DQS_DN<0>")
	)
	(segment
		(start 331.06995 -297.237658)
		(end 330.856082 -297.762168)
		(width 0.1524)
		(layer "F.Cu")
		(net "M_A_CPU0_SA_DQS_DN<0>")
	)
	(segment
		(start 307.356256 -312.752994)
		(end 307.781452 -312.327798)
		(width 0.20066)
		(layer "F.Cu")
		(net "M_A_CPU0_SA_DQS_DN<0>")
	)
	(segment
		(start 314.103004 -312.491628)
		(end 311.989216 -312.491628)
		(width 0.1016)
		(layer "F.Cu")
		(net "M_A_CPU0_SA_DQS_DN<0>")
	)
	(segment
		(start 318.330834 -309.298086)
		(end 317.904876 -309.724044)
		(width 0.20066)
		(layer "F.Cu")
		(net "M_A_CPU0_SA_DQS_DN<0>")
	)
	(segment
		(start 315.85027 -311.77865)
		(end 315.85027 -311.954672)
		(width 0.20066)
		(layer "F.Cu")
		(net "M_A_CPU0_SA_DQS_DN<0>")
	)
	(segment
		(start 307.781452 -312.327798)
		(end 308.079394 -312.327798)
		(width 0.20066)
		(layer "F.Cu")
		(net "M_A_CPU0_SA_DQS_DN<0>")
	)
	(segment
		(start 310.948324 -312.762646)
		(end 309.922418 -312.337704)
		(width 0.20066)
		(layer "F.Cu")
		(net "M_A_CPU0_SA_DQS_DN<0>")
	)
	(arc
		(start 333.583534 -278.11222)
		(mid 333.542896 -278.131381)
		(end 333.498444 -278.137874)
		(width 0.088646)
		(layer "F.Cu")
		(net "M_A_CPU0_SA_DQS_DN<0>")
	)
	(arc
		(start 333.745586 -277.85949)
		(mid 333.690964 -278.002776)
		(end 333.583534 -278.11222)
		(width 0.088646)
		(layer "F.Cu")
		(net "M_A_CPU0_SA_DQS_DN<0>")
	)
	(segment
		(start 304.319178 -304.833528)
		(end 303.026064 -304.833528)
		(width 0.20066)
		(layer "F.Cu")
		(net "M_A_CPU0_SA_DQ<9>")
	)
	(segment
		(start 307.18633 -305.266598)
		(end 306.761388 -304.841656)
		(width 0.20066)
		(layer "F.Cu")
		(net "M_A_CPU0_SA_DQ<9>")
	)
	(segment
		(start 302.603408 -305.518312)
		(end 302.21936 -305.518312)
		(width 0.20066)
		(layer "F.Cu")
		(net "M_A_CPU0_SA_DQ<9>")
	)
	(segment
		(start 309.992014 -305.266598)
		(end 308.887114 -305.266598)
		(width 0.20066)
		(layer "F.Cu")
		(net "M_A_CPU0_SA_DQ<9>")
	)
	(segment
		(start 336.665316 -270.475456)
		(end 336.665316 -271.011142)
		(width 0.20066)
		(layer "F.Cu")
		(net "M_A_CPU0_SA_DQ<9>")
	)
	(segment
		(start 306.761388 -304.841656)
		(end 306.644294 -304.841656)
		(width 0.20066)
		(layer "F.Cu")
		(net "M_A_CPU0_SA_DQ<9>")
	)
	(segment
		(start 301.967392 -305.266344)
		(end 301.967138 -305.266598)
		(width 0.20066)
		(layer "F.Cu")
		(net "M_A_CPU0_SA_DQ<9>")
	)
	(segment
		(start 302.837596 -305.021996)
		(end 302.837596 -305.284124)
		(width 0.20066)
		(layer "F.Cu")
		(net "M_A_CPU0_SA_DQ<9>")
	)
	(segment
		(start 304.358294 -304.833528)
		(end 304.319178 -304.833528)
		(width 0.101854)
		(layer "F.Cu")
		(net "M_A_CPU0_SA_DQ<9>")
	)
	(segment
		(start 308.887114 -305.266598)
		(end 307.18633 -305.266598)
		(width 0.20066)
		(layer "F.Cu")
		(net "M_A_CPU0_SA_DQ<9>")
	)
	(segment
		(start 304.366422 -304.841656)
		(end 304.358294 -304.833528)
		(width 0.101854)
		(layer "F.Cu")
		(net "M_A_CPU0_SA_DQ<9>")
	)
	(segment
		(start 302.837596 -305.284124)
		(end 302.603408 -305.518312)
		(width 0.20066)
		(layer "F.Cu")
		(net "M_A_CPU0_SA_DQ<9>")
	)
	(segment
		(start 336.665316 -271.011142)
		(end 336.665062 -271.011396)
		(width 0.20066)
		(layer "F.Cu")
		(net "M_A_CPU0_SA_DQ<9>")
	)
	(segment
		(start 303.026064 -304.833528)
		(end 302.837596 -305.021996)
		(width 0.20066)
		(layer "F.Cu")
		(net "M_A_CPU0_SA_DQ<9>")
	)
	(segment
		(start 304.37328 -304.841656)
		(end 304.366422 -304.841656)
		(width 0.101854)
		(layer "F.Cu")
		(net "M_A_CPU0_SA_DQ<9>")
	)
	(segment
		(start 306.58308 -304.841656)
		(end 304.37328 -304.841656)
		(width 0.1016)
		(layer "F.Cu")
		(net "M_A_CPU0_SA_DQ<9>")
	)
	(segment
		(start 301.967138 -305.266598)
		(end 301.343314 -305.266598)
		(width 0.20066)
		(layer "F.Cu")
		(net "M_A_CPU0_SA_DQ<9>")
	)
	(segment
		(start 306.644294 -304.841656)
		(end 306.58308 -304.841656)
		(width 0.101854)
		(layer "F.Cu")
		(net "M_A_CPU0_SA_DQ<9>")
	)
	(segment
		(start 302.21936 -305.518312)
		(end 301.967392 -305.266344)
		(width 0.20066)
		(layer "F.Cu")
		(net "M_A_CPU0_SA_DQ<9>")
	)
	(segment
		(start 326.59574 -280.62682)
		(end 326.449182 -280.980642)
		(width 0.18288)
		(layer "In2.Cu")
		(net "M_A_CPU0_SA_DQ<9>")
	)
	(segment
		(start 311.661556 -304.688494)
		(end 311.519316 -304.546254)
		(width 0.18288)
		(layer "In2.Cu")
		(net "M_A_CPU0_SA_DQ<9>")
	)
	(segment
		(start 334.87614 -271.694656)
		(end 333.700374 -271.694656)
		(width 0.088646)
		(layer "In2.Cu")
		(net "M_A_CPU0_SA_DQ<9>")
	)
	(segment
		(start 334.928464 -271.642332)
		(end 334.87614 -271.694656)
		(width 0.088646)
		(layer "In2.Cu")
		(net "M_A_CPU0_SA_DQ<9>")
	)
	(segment
		(start 310.621934 -304.636678)
		(end 309.992014 -305.266598)
		(width 0.18288)
		(layer "In2.Cu")
		(net "M_A_CPU0_SA_DQ<9>")
	)
	(segment
		(start 329.99807 -277.22449)
		(end 326.59574 -280.62682)
		(width 0.18288)
		(layer "In2.Cu")
		(net "M_A_CPU0_SA_DQ<9>")
	)
	(segment
		(start 312.18505 -304.841656)
		(end 312.031888 -304.688494)
		(width 0.18288)
		(layer "In2.Cu")
		(net "M_A_CPU0_SA_DQ<9>")
	)
	(segment
		(start 319.268094 -294.526716)
		(end 317.915036 -297.795188)
		(width 0.18288)
		(layer "In2.Cu")
		(net "M_A_CPU0_SA_DQ<9>")
	)
	(segment
		(start 325.152512 -284.110938)
		(end 323.499988 -285.763462)
		(width 0.18288)
		(layer "In2.Cu")
		(net "M_A_CPU0_SA_DQ<9>")
	)
	(segment
		(start 323.499988 -285.763462)
		(end 320.298826 -293.49573)
		(width 0.18288)
		(layer "In2.Cu")
		(net "M_A_CPU0_SA_DQ<9>")
	)
	(segment
		(start 331.28966 -274.10537)
		(end 329.99807 -277.22449)
		(width 0.18288)
		(layer "In2.Cu")
		(net "M_A_CPU0_SA_DQ<9>")
	)
	(segment
		(start 336.665062 -271.011396)
		(end 336.036158 -271.484598)
		(width 0.088646)
		(layer "In2.Cu")
		(net "M_A_CPU0_SA_DQ<9>")
	)
	(segment
		(start 312.031888 -304.688494)
		(end 311.661556 -304.688494)
		(width 0.18288)
		(layer "In2.Cu")
		(net "M_A_CPU0_SA_DQ<9>")
	)
	(segment
		(start 315.074046 -304.94605)
		(end 314.441078 -304.94605)
		(width 0.18288)
		(layer "In2.Cu")
		(net "M_A_CPU0_SA_DQ<9>")
	)
	(segment
		(start 311.519316 -304.546254)
		(end 311.519316 -304.295556)
		(width 0.18288)
		(layer "In2.Cu")
		(net "M_A_CPU0_SA_DQ<9>")
	)
	(segment
		(start 311.359296 -304.135536)
		(end 310.781954 -304.135536)
		(width 0.18288)
		(layer "In2.Cu")
		(net "M_A_CPU0_SA_DQ<9>")
	)
	(segment
		(start 333.700374 -271.694656)
		(end 333.525114 -271.869916)
		(width 0.088646)
		(layer "In2.Cu")
		(net "M_A_CPU0_SA_DQ<9>")
	)
	(segment
		(start 333.525114 -271.869916)
		(end 331.28966 -274.10537)
		(width 0.18288)
		(layer "In2.Cu")
		(net "M_A_CPU0_SA_DQ<9>")
	)
	(segment
		(start 326.449182 -280.980642)
		(end 325.152512 -284.110938)
		(width 0.18288)
		(layer "In2.Cu")
		(net "M_A_CPU0_SA_DQ<9>")
	)
	(segment
		(start 320.298826 -293.49573)
		(end 319.268094 -294.526716)
		(width 0.18288)
		(layer "In2.Cu")
		(net "M_A_CPU0_SA_DQ<9>")
	)
	(segment
		(start 310.621934 -304.295556)
		(end 310.621934 -304.636678)
		(width 0.18288)
		(layer "In2.Cu")
		(net "M_A_CPU0_SA_DQ<9>")
	)
	(segment
		(start 335.068164 -271.500854)
		(end 335.059274 -271.505934)
		(width 0.088646)
		(layer "In2.Cu")
		(net "M_A_CPU0_SA_DQ<9>")
	)
	(segment
		(start 336.036158 -271.484598)
		(end 336.007964 -271.500854)
		(width 0.088646)
		(layer "In2.Cu")
		(net "M_A_CPU0_SA_DQ<9>")
	)
	(segment
		(start 314.441078 -304.94605)
		(end 314.336684 -304.841656)
		(width 0.18288)
		(layer "In2.Cu")
		(net "M_A_CPU0_SA_DQ<9>")
	)
	(segment
		(start 314.336684 -304.841656)
		(end 312.18505 -304.841656)
		(width 0.18288)
		(layer "In2.Cu")
		(net "M_A_CPU0_SA_DQ<9>")
	)
	(segment
		(start 310.781954 -304.135536)
		(end 310.621934 -304.295556)
		(width 0.18288)
		(layer "In2.Cu")
		(net "M_A_CPU0_SA_DQ<9>")
	)
	(segment
		(start 317.915036 -300.665388)
		(end 316.897004 -303.123092)
		(width 0.18288)
		(layer "In2.Cu")
		(net "M_A_CPU0_SA_DQ<9>")
	)
	(segment
		(start 311.519316 -304.295556)
		(end 311.359296 -304.135536)
		(width 0.18288)
		(layer "In2.Cu")
		(net "M_A_CPU0_SA_DQ<9>")
	)
	(segment
		(start 317.915036 -297.795188)
		(end 317.915036 -300.665388)
		(width 0.18288)
		(layer "In2.Cu")
		(net "M_A_CPU0_SA_DQ<9>")
	)
	(segment
		(start 316.897004 -303.123092)
		(end 315.074046 -304.94605)
		(width 0.18288)
		(layer "In2.Cu")
		(net "M_A_CPU0_SA_DQ<9>")
	)
	(arc
		(start 336.007964 -271.500854)
		(mid 335.725262 -271.576596)
		(end 335.44256 -271.500854)
		(width 0.088646)
		(layer "In2.Cu")
		(net "M_A_CPU0_SA_DQ<9>")
	)
	(arc
		(start 335.44256 -271.500854)
		(mid 335.255362 -271.450711)
		(end 335.068164 -271.500854)
		(width 0.088646)
		(layer "In2.Cu")
		(net "M_A_CPU0_SA_DQ<9>")
	)
	(arc
		(start 335.059274 -271.505934)
		(mid 334.985123 -271.565747)
		(end 334.928464 -271.642332)
		(width 0.088646)
		(layer "In2.Cu")
		(net "M_A_CPU0_SA_DQ<9>")
	)
	(segment
		(start 301.967138 -306.96662)
		(end 301.343314 -306.96662)
		(width 0.20066)
		(layer "F.Cu")
		(net "M_A_CPU0_SA_DQ<8>")
	)
	(segment
		(start 307.269388 -306.541678)
		(end 306.644294 -306.541678)
		(width 0.20066)
		(layer "F.Cu")
		(net "M_A_CPU0_SA_DQ<8>")
	)
	(segment
		(start 302.837596 -306.984146)
		(end 302.603408 -307.218334)
		(width 0.20066)
		(layer "F.Cu")
		(net "M_A_CPU0_SA_DQ<8>")
	)
	(segment
		(start 337.134962 -271.824958)
		(end 337.135216 -271.825212)
		(width 0.20066)
		(layer "F.Cu")
		(net "M_A_CPU0_SA_DQ<8>")
	)
	(segment
		(start 307.69433 -306.96662)
		(end 307.269388 -306.541678)
		(width 0.20066)
		(layer "F.Cu")
		(net "M_A_CPU0_SA_DQ<8>")
	)
	(segment
		(start 308.887114 -306.96662)
		(end 307.69433 -306.96662)
		(width 0.20066)
		(layer "F.Cu")
		(net "M_A_CPU0_SA_DQ<8>")
	)
	(segment
		(start 304.355754 -306.541678)
		(end 304.34407 -306.529994)
		(width 0.101854)
		(layer "F.Cu")
		(net "M_A_CPU0_SA_DQ<8>")
	)
	(segment
		(start 304.34407 -306.529994)
		(end 304.319178 -306.529994)
		(width 0.101854)
		(layer "F.Cu")
		(net "M_A_CPU0_SA_DQ<8>")
	)
	(segment
		(start 304.37328 -306.541678)
		(end 304.355754 -306.541678)
		(width 0.101854)
		(layer "F.Cu")
		(net "M_A_CPU0_SA_DQ<8>")
	)
	(segment
		(start 302.603408 -307.218334)
		(end 302.21936 -307.218334)
		(width 0.20066)
		(layer "F.Cu")
		(net "M_A_CPU0_SA_DQ<8>")
	)
	(segment
		(start 302.21936 -307.218334)
		(end 301.967392 -306.966366)
		(width 0.20066)
		(layer "F.Cu")
		(net "M_A_CPU0_SA_DQ<8>")
	)
	(segment
		(start 337.134962 -271.289272)
		(end 337.134962 -271.824958)
		(width 0.20066)
		(layer "F.Cu")
		(net "M_A_CPU0_SA_DQ<8>")
	)
	(segment
		(start 303.029366 -306.529994)
		(end 302.837596 -306.721764)
		(width 0.20066)
		(layer "F.Cu")
		(net "M_A_CPU0_SA_DQ<8>")
	)
	(segment
		(start 304.319178 -306.529994)
		(end 303.029366 -306.529994)
		(width 0.20066)
		(layer "F.Cu")
		(net "M_A_CPU0_SA_DQ<8>")
	)
	(segment
		(start 302.837596 -306.721764)
		(end 302.837596 -306.984146)
		(width 0.20066)
		(layer "F.Cu")
		(net "M_A_CPU0_SA_DQ<8>")
	)
	(segment
		(start 309.992014 -306.96662)
		(end 308.887114 -306.96662)
		(width 0.20066)
		(layer "F.Cu")
		(net "M_A_CPU0_SA_DQ<8>")
	)
	(segment
		(start 306.55768 -306.541678)
		(end 304.37328 -306.541678)
		(width 0.1016)
		(layer "F.Cu")
		(net "M_A_CPU0_SA_DQ<8>")
	)
	(segment
		(start 301.967392 -306.966366)
		(end 301.967138 -306.96662)
		(width 0.20066)
		(layer "F.Cu")
		(net "M_A_CPU0_SA_DQ<8>")
	)
	(segment
		(start 306.644294 -306.541678)
		(end 306.55768 -306.541678)
		(width 0.101854)
		(layer "F.Cu")
		(net "M_A_CPU0_SA_DQ<8>")
	)
	(segment
		(start 320.701162 -293.852346)
		(end 319.6717 -294.882062)
		(width 0.18288)
		(layer "In2.Cu")
		(net "M_A_CPU0_SA_DQ<8>")
	)
	(segment
		(start 330.253086 -277.511764)
		(end 327.151492 -280.613358)
		(width 0.18288)
		(layer "In2.Cu")
		(net "M_A_CPU0_SA_DQ<8>")
	)
	(segment
		(start 318.423036 -300.795436)
		(end 317.347854 -303.391062)
		(width 0.18288)
		(layer "In2.Cu")
		(net "M_A_CPU0_SA_DQ<8>")
	)
	(segment
		(start 314.656978 -305.52771)
		(end 314.493148 -305.69154)
		(width 0.18288)
		(layer "In2.Cu")
		(net "M_A_CPU0_SA_DQ<8>")
	)
	(segment
		(start 335.068926 -272.14957)
		(end 335.068164 -272.14957)
		(width 0.088646)
		(layer "In2.Cu")
		(net "M_A_CPU0_SA_DQ<8>")
	)
	(segment
		(start 333.158084 -272.72615)
		(end 332.020926 -273.863308)
		(width 0.088646)
		(layer "In2.Cu")
		(net "M_A_CPU0_SA_DQ<8>")
	)
	(segment
		(start 336.0166 -272.154396)
		(end 336.008218 -272.14957)
		(width 0.088646)
		(layer "In2.Cu")
		(net "M_A_CPU0_SA_DQ<8>")
	)
	(segment
		(start 315.211206 -305.52771)
		(end 314.656978 -305.52771)
		(width 0.18288)
		(layer "In2.Cu")
		(net "M_A_CPU0_SA_DQ<8>")
	)
	(segment
		(start 325.583296 -284.398974)
		(end 323.93382 -286.04845)
		(width 0.18288)
		(layer "In2.Cu")
		(net "M_A_CPU0_SA_DQ<8>")
	)
	(segment
		(start 314.493148 -305.69154)
		(end 312.302398 -305.69154)
		(width 0.18288)
		(layer "In2.Cu")
		(net "M_A_CPU0_SA_DQ<8>")
	)
	(segment
		(start 337.44789 -271.825212)
		(end 337.50504 -271.882362)
		(width 0.088646)
		(layer "In2.Cu")
		(net "M_A_CPU0_SA_DQ<8>")
	)
	(segment
		(start 327.151492 -280.613358)
		(end 326.999346 -280.980642)
		(width 0.18288)
		(layer "In2.Cu")
		(net "M_A_CPU0_SA_DQ<8>")
	)
	(segment
		(start 326.999346 -280.980642)
		(end 325.583296 -284.398974)
		(width 0.18288)
		(layer "In2.Cu")
		(net "M_A_CPU0_SA_DQ<8>")
	)
	(segment
		(start 336.948018 -272.14957)
		(end 336.937604 -272.143474)
		(width 0.088646)
		(layer "In2.Cu")
		(net "M_A_CPU0_SA_DQ<8>")
	)
	(segment
		(start 318.423036 -297.896534)
		(end 318.423036 -300.795436)
		(width 0.18288)
		(layer "In2.Cu")
		(net "M_A_CPU0_SA_DQ<8>")
	)
	(segment
		(start 311.855612 -305.79568)
		(end 311.56148 -305.9176)
		(width 0.18288)
		(layer "In2.Cu")
		(net "M_A_CPU0_SA_DQ<8>")
	)
	(segment
		(start 335.068164 -272.14957)
		(end 335.053432 -272.140934)
		(width 0.088646)
		(layer "In2.Cu")
		(net "M_A_CPU0_SA_DQ<8>")
	)
	(segment
		(start 311.56148 -305.9176)
		(end 309.992014 -306.96662)
		(width 0.18288)
		(layer "In2.Cu")
		(net "M_A_CPU0_SA_DQ<8>")
	)
	(segment
		(start 317.347854 -303.391062)
		(end 315.211206 -305.52771)
		(width 0.18288)
		(layer "In2.Cu")
		(net "M_A_CPU0_SA_DQ<8>")
	)
	(segment
		(start 332.020926 -273.863308)
		(end 331.583792 -274.300442)
		(width 0.18288)
		(layer "In2.Cu")
		(net "M_A_CPU0_SA_DQ<8>")
	)
	(segment
		(start 319.6717 -294.882062)
		(end 318.423036 -297.896534)
		(width 0.18288)
		(layer "In2.Cu")
		(net "M_A_CPU0_SA_DQ<8>")
	)
	(segment
		(start 331.583792 -274.300442)
		(end 330.253086 -277.511764)
		(width 0.18288)
		(layer "In2.Cu")
		(net "M_A_CPU0_SA_DQ<8>")
	)
	(segment
		(start 323.93382 -286.04845)
		(end 320.701162 -293.852346)
		(width 0.18288)
		(layer "In2.Cu")
		(net "M_A_CPU0_SA_DQ<8>")
	)
	(segment
		(start 312.302398 -305.69154)
		(end 311.855612 -305.79568)
		(width 0.18288)
		(layer "In2.Cu")
		(net "M_A_CPU0_SA_DQ<8>")
	)
	(segment
		(start 337.135216 -271.825212)
		(end 337.44789 -271.825212)
		(width 0.088646)
		(layer "In2.Cu")
		(net "M_A_CPU0_SA_DQ<8>")
	)
	(segment
		(start 334.613758 -272.104358)
		(end 333.231236 -272.677128)
		(width 0.088646)
		(layer "In2.Cu")
		(net "M_A_CPU0_SA_DQ<8>")
	)
	(arc
		(start 335.053432 -272.140934)
		(mid 334.88122 -272.081669)
		(end 334.699102 -272.080228)
		(width 0.088646)
		(layer "In2.Cu")
		(net "M_A_CPU0_SA_DQ<8>")
	)
	(arc
		(start 336.937604 -272.143474)
		(mid 336.659172 -272.07366)
		(end 336.38236 -272.14957)
		(width 0.088646)
		(layer "In2.Cu")
		(net "M_A_CPU0_SA_DQ<8>")
	)
	(arc
		(start 337.322414 -272.14957)
		(mid 337.135216 -272.199713)
		(end 336.948018 -272.14957)
		(width 0.088646)
		(layer "In2.Cu")
		(net "M_A_CPU0_SA_DQ<8>")
	)
	(arc
		(start 336.008218 -272.14957)
		(mid 335.72577 -272.073955)
		(end 335.443322 -272.14957)
		(width 0.088646)
		(layer "In2.Cu")
		(net "M_A_CPU0_SA_DQ<8>")
	)
	(arc
		(start 336.38236 -272.14957)
		(mid 336.200109 -272.199681)
		(end 336.0166 -272.154396)
		(width 0.088646)
		(layer "In2.Cu")
		(net "M_A_CPU0_SA_DQ<8>")
	)
	(arc
		(start 337.50504 -271.882362)
		(mid 337.444097 -272.036725)
		(end 337.322414 -272.14957)
		(width 0.088646)
		(layer "In2.Cu")
		(net "M_A_CPU0_SA_DQ<8>")
	)
	(arc
		(start 335.443322 -272.14957)
		(mid 335.256124 -272.199713)
		(end 335.068926 -272.14957)
		(width 0.088646)
		(layer "In2.Cu")
		(net "M_A_CPU0_SA_DQ<8>")
	)
	(arc
		(start 334.699102 -272.080228)
		(mid 334.655714 -272.089756)
		(end 334.613758 -272.104358)
		(width 0.088646)
		(layer "In2.Cu")
		(net "M_A_CPU0_SA_DQ<8>")
	)
	(arc
		(start 333.231236 -272.677128)
		(mid 333.192261 -272.698056)
		(end 333.158084 -272.72615)
		(width 0.088646)
		(layer "In2.Cu")
		(net "M_A_CPU0_SA_DQ<8>")
	)
	(segment
		(start 328.70521 -294.868092)
		(end 323.853556 -299.719746)
		(width 0.20066)
		(layer "F.Cu")
		(net "M_A_CPU0_SA_DQ<7>")
	)
	(segment
		(start 331.540866 -277.005288)
		(end 331.138784 -277.40737)
		(width 0.088646)
		(layer "F.Cu")
		(net "M_A_CPU0_SA_DQ<7>")
	)
	(segment
		(start 317.07328 -302.28413)
		(end 317.07328 -302.568102)
		(width 0.20066)
		(layer "F.Cu")
		(net "M_A_CPU0_SA_DQ<7>")
	)
	(segment
		(start 310.357266 -308.2417)
		(end 310.782462 -307.816504)
		(width 0.20066)
		(layer "F.Cu")
		(net "M_A_CPU0_SA_DQ<7>")
	)
	(segment
		(start 307.25491 -307.942488)
		(end 307.25491 -308.102508)
		(width 0.20066)
		(layer "F.Cu")
		(net "M_A_CPU0_SA_DQ<7>")
	)
	(segment
		(start 316.439042 -303.945544)
		(end 316.439042 -304.229516)
		(width 0.20066)
		(layer "F.Cu")
		(net "M_A_CPU0_SA_DQ<7>")
	)
	(segment
		(start 307.784246 -308.2417)
		(end 307.82768 -308.2417)
		(width 0.101854)
		(layer "F.Cu")
		(net "M_A_CPU0_SA_DQ<7>")
	)
	(segment
		(start 319.303908 -300.053502)
		(end 319.08496 -300.27245)
		(width 0.20066)
		(layer "F.Cu")
		(net "M_A_CPU0_SA_DQ<7>")
	)
	(segment
		(start 316.439042 -304.229516)
		(end 315.142372 -305.526186)
		(width 0.20066)
		(layer "F.Cu")
		(net "M_A_CPU0_SA_DQ<7>")
	)
	(segment
		(start 307.401214 -308.248812)
		(end 307.76291 -308.248812)
		(width 0.20066)
		(layer "F.Cu")
		(net "M_A_CPU0_SA_DQ<7>")
	)
	(segment
		(start 311.111646 -307.816504)
		(end 311.442608 -308.147466)
		(width 0.20066)
		(layer "F.Cu")
		(net "M_A_CPU0_SA_DQ<7>")
	)
	(segment
		(start 317.225934 -303.442624)
		(end 316.941962 -303.442624)
		(width 0.20066)
		(layer "F.Cu")
		(net "M_A_CPU0_SA_DQ<7>")
	)
	(segment
		(start 330.110846 -278.6888)
		(end 330.063856 -278.776938)
		(width 0.1016)
		(layer "F.Cu")
		(net "M_A_CPU0_SA_DQ<7>")
	)
	(segment
		(start 319.456562 -300.928024)
		(end 319.456562 -301.211996)
		(width 0.20066)
		(layer "F.Cu")
		(net "M_A_CPU0_SA_DQ<7>")
	)
	(segment
		(start 307.128672 -307.816758)
		(end 307.128926 -307.816504)
		(width 0.20066)
		(layer "F.Cu")
		(net "M_A_CPU0_SA_DQ<7>")
	)
	(segment
		(start 318.231774 -302.436784)
		(end 317.947802 -302.436784)
		(width 0.20066)
		(layer "F.Cu")
		(net "M_A_CPU0_SA_DQ<7>")
	)
	(segment
		(start 307.82768 -308.2417)
		(end 310.01208 -308.2417)
		(width 0.1016)
		(layer "F.Cu")
		(net "M_A_CPU0_SA_DQ<7>")
	)
	(segment
		(start 316.941962 -303.442624)
		(end 316.57036 -303.071022)
		(width 0.20066)
		(layer "F.Cu")
		(net "M_A_CPU0_SA_DQ<7>")
	)
	(segment
		(start 314.314332 -307.816758)
		(end 312.987182 -307.816758)
		(width 0.20066)
		(layer "F.Cu")
		(net "M_A_CPU0_SA_DQ<7>")
	)
	(segment
		(start 333.375762 -275.79828)
		(end 332.878176 -275.79828)
		(width 0.088646)
		(layer "F.Cu")
		(net "M_A_CPU0_SA_DQ<7>")
	)
	(segment
		(start 320.948812 -299.719746)
		(end 320.243454 -300.425104)
		(width 0.20066)
		(layer "F.Cu")
		(net "M_A_CPU0_SA_DQ<7>")
	)
	(segment
		(start 320.243454 -300.425104)
		(end 319.959482 -300.425104)
		(width 0.20066)
		(layer "F.Cu")
		(net "M_A_CPU0_SA_DQ<7>")
	)
	(segment
		(start 317.444882 -302.939704)
		(end 317.444882 -303.223676)
		(width 0.20066)
		(layer "F.Cu")
		(net "M_A_CPU0_SA_DQ<7>")
	)
	(segment
		(start 315.142372 -305.526186)
		(end 315.142372 -306.988718)
		(width 0.20066)
		(layer "F.Cu")
		(net "M_A_CPU0_SA_DQ<7>")
	)
	(segment
		(start 315.142372 -306.988718)
		(end 314.314332 -307.816758)
		(width 0.20066)
		(layer "F.Cu")
		(net "M_A_CPU0_SA_DQ<7>")
	)
	(segment
		(start 316.06744 -303.573942)
		(end 316.439042 -303.945544)
		(width 0.20066)
		(layer "F.Cu")
		(net "M_A_CPU0_SA_DQ<7>")
	)
	(segment
		(start 307.128926 -307.816504)
		(end 307.25491 -307.942488)
		(width 0.20066)
		(layer "F.Cu")
		(net "M_A_CPU0_SA_DQ<7>")
	)
	(segment
		(start 318.450722 -301.933864)
		(end 318.450722 -302.217836)
		(width 0.20066)
		(layer "F.Cu")
		(net "M_A_CPU0_SA_DQ<7>")
	)
	(segment
		(start 319.08496 -300.556422)
		(end 319.456562 -300.928024)
		(width 0.20066)
		(layer "F.Cu")
		(net "M_A_CPU0_SA_DQ<7>")
	)
	(segment
		(start 317.444882 -303.223676)
		(end 317.225934 -303.442624)
		(width 0.20066)
		(layer "F.Cu")
		(net "M_A_CPU0_SA_DQ<7>")
	)
	(segment
		(start 331.138784 -277.660862)
		(end 330.868782 -277.930864)
		(width 0.088646)
		(layer "F.Cu")
		(net "M_A_CPU0_SA_DQ<7>")
	)
	(segment
		(start 319.08496 -300.27245)
		(end 319.08496 -300.556422)
		(width 0.20066)
		(layer "F.Cu")
		(net "M_A_CPU0_SA_DQ<7>")
	)
	(segment
		(start 317.07328 -302.568102)
		(end 317.444882 -302.939704)
		(width 0.20066)
		(layer "F.Cu")
		(net "M_A_CPU0_SA_DQ<7>")
	)
	(segment
		(start 318.450722 -302.217836)
		(end 318.231774 -302.436784)
		(width 0.20066)
		(layer "F.Cu")
		(net "M_A_CPU0_SA_DQ<7>")
	)
	(segment
		(start 330.063856 -278.776938)
		(end 329.43038 -281.947112)
		(width 0.1016)
		(layer "F.Cu")
		(net "M_A_CPU0_SA_DQ<7>")
	)
	(segment
		(start 307.76291 -308.248812)
		(end 307.777134 -308.248812)
		(width 0.101854)
		(layer "F.Cu")
		(net "M_A_CPU0_SA_DQ<7>")
	)
	(segment
		(start 305.443382 -307.816758)
		(end 307.128672 -307.816758)
		(width 0.20066)
		(layer "F.Cu")
		(net "M_A_CPU0_SA_DQ<7>")
	)
	(segment
		(start 334.72374 -275.940774)
		(end 334.433418 -275.772372)
		(width 0.088646)
		(layer "F.Cu")
		(net "M_A_CPU0_SA_DQ<7>")
	)
	(segment
		(start 316.57036 -303.071022)
		(end 316.286388 -303.071022)
		(width 0.20066)
		(layer "F.Cu")
		(net "M_A_CPU0_SA_DQ<7>")
	)
	(segment
		(start 310.088026 -308.2417)
		(end 310.357266 -308.2417)
		(width 0.20066)
		(layer "F.Cu")
		(net "M_A_CPU0_SA_DQ<7>")
	)
	(segment
		(start 332.878176 -275.79828)
		(end 331.671168 -277.005288)
		(width 0.088646)
		(layer "F.Cu")
		(net "M_A_CPU0_SA_DQ<7>")
	)
	(segment
		(start 319.58788 -300.053502)
		(end 319.303908 -300.053502)
		(width 0.20066)
		(layer "F.Cu")
		(net "M_A_CPU0_SA_DQ<7>")
	)
	(segment
		(start 317.947802 -302.436784)
		(end 317.5762 -302.065182)
		(width 0.20066)
		(layer "F.Cu")
		(net "M_A_CPU0_SA_DQ<7>")
	)
	(segment
		(start 335.255362 -276.172676)
		(end 334.803242 -275.980652)
		(width 0.088646)
		(layer "F.Cu")
		(net "M_A_CPU0_SA_DQ<7>")
	)
	(segment
		(start 318.07912 -301.27829)
		(end 318.07912 -301.562262)
		(width 0.20066)
		(layer "F.Cu")
		(net "M_A_CPU0_SA_DQ<7>")
	)
	(segment
		(start 323.853556 -299.719746)
		(end 320.948812 -299.719746)
		(width 0.20066)
		(layer "F.Cu")
		(net "M_A_CPU0_SA_DQ<7>")
	)
	(segment
		(start 319.456562 -301.211996)
		(end 319.237614 -301.430944)
		(width 0.20066)
		(layer "F.Cu")
		(net "M_A_CPU0_SA_DQ<7>")
	)
	(segment
		(start 329.43038 -281.947112)
		(end 329.43038 -294.142922)
		(width 0.1016)
		(layer "F.Cu")
		(net "M_A_CPU0_SA_DQ<7>")
	)
	(segment
		(start 317.292228 -302.065182)
		(end 317.07328 -302.28413)
		(width 0.20066)
		(layer "F.Cu")
		(net "M_A_CPU0_SA_DQ<7>")
	)
	(segment
		(start 318.953642 -301.430944)
		(end 318.58204 -301.059342)
		(width 0.20066)
		(layer "F.Cu")
		(net "M_A_CPU0_SA_DQ<7>")
	)
	(segment
		(start 316.286388 -303.071022)
		(end 316.06744 -303.28997)
		(width 0.20066)
		(layer "F.Cu")
		(net "M_A_CPU0_SA_DQ<7>")
	)
	(segment
		(start 331.138784 -277.40737)
		(end 331.138784 -277.660862)
		(width 0.088646)
		(layer "F.Cu")
		(net "M_A_CPU0_SA_DQ<7>")
	)
	(segment
		(start 311.828434 -308.147466)
		(end 312.159142 -307.816758)
		(width 0.20066)
		(layer "F.Cu")
		(net "M_A_CPU0_SA_DQ<7>")
	)
	(segment
		(start 312.159142 -307.816758)
		(end 312.987182 -307.816758)
		(width 0.20066)
		(layer "F.Cu")
		(net "M_A_CPU0_SA_DQ<7>")
	)
	(segment
		(start 334.084422 -275.771864)
		(end 333.951834 -275.848318)
		(width 0.088646)
		(layer "F.Cu")
		(net "M_A_CPU0_SA_DQ<7>")
	)
	(segment
		(start 311.442608 -308.147466)
		(end 311.828434 -308.147466)
		(width 0.20066)
		(layer "F.Cu")
		(net "M_A_CPU0_SA_DQ<7>")
	)
	(segment
		(start 331.671168 -277.005288)
		(end 331.540866 -277.005288)
		(width 0.088646)
		(layer "F.Cu")
		(net "M_A_CPU0_SA_DQ<7>")
	)
	(segment
		(start 317.5762 -302.065182)
		(end 317.292228 -302.065182)
		(width 0.20066)
		(layer "F.Cu")
		(net "M_A_CPU0_SA_DQ<7>")
	)
	(segment
		(start 310.01208 -308.2417)
		(end 310.088026 -308.2417)
		(width 0.101854)
		(layer "F.Cu")
		(net "M_A_CPU0_SA_DQ<7>")
	)
	(segment
		(start 330.868782 -277.930864)
		(end 330.110846 -278.6888)
		(width 0.1016)
		(layer "F.Cu")
		(net "M_A_CPU0_SA_DQ<7>")
	)
	(segment
		(start 318.58204 -301.059342)
		(end 318.298068 -301.059342)
		(width 0.20066)
		(layer "F.Cu")
		(net "M_A_CPU0_SA_DQ<7>")
	)
	(segment
		(start 316.06744 -303.28997)
		(end 316.06744 -303.573942)
		(width 0.20066)
		(layer "F.Cu")
		(net "M_A_CPU0_SA_DQ<7>")
	)
	(segment
		(start 329.43038 -294.142922)
		(end 328.70521 -294.868092)
		(width 0.1016)
		(layer "F.Cu")
		(net "M_A_CPU0_SA_DQ<7>")
	)
	(segment
		(start 307.25491 -308.102508)
		(end 307.401214 -308.248812)
		(width 0.20066)
		(layer "F.Cu")
		(net "M_A_CPU0_SA_DQ<7>")
	)
	(segment
		(start 319.959482 -300.425104)
		(end 319.58788 -300.053502)
		(width 0.20066)
		(layer "F.Cu")
		(net "M_A_CPU0_SA_DQ<7>")
	)
	(segment
		(start 318.07912 -301.562262)
		(end 318.450722 -301.933864)
		(width 0.20066)
		(layer "F.Cu")
		(net "M_A_CPU0_SA_DQ<7>")
	)
	(segment
		(start 319.237614 -301.430944)
		(end 318.953642 -301.430944)
		(width 0.20066)
		(layer "F.Cu")
		(net "M_A_CPU0_SA_DQ<7>")
	)
	(segment
		(start 307.777134 -308.248812)
		(end 307.784246 -308.2417)
		(width 0.101854)
		(layer "F.Cu")
		(net "M_A_CPU0_SA_DQ<7>")
	)
	(segment
		(start 318.298068 -301.059342)
		(end 318.07912 -301.27829)
		(width 0.20066)
		(layer "F.Cu")
		(net "M_A_CPU0_SA_DQ<7>")
	)
	(segment
		(start 310.782462 -307.816504)
		(end 311.111646 -307.816504)
		(width 0.20066)
		(layer "F.Cu")
		(net "M_A_CPU0_SA_DQ<7>")
	)
	(arc
		(start 334.433418 -275.772372)
		(mid 334.258979 -275.725227)
		(end 334.084422 -275.771864)
		(width 0.088646)
		(layer "F.Cu")
		(net "M_A_CPU0_SA_DQ<7>")
	)
	(arc
		(start 334.803242 -275.980652)
		(mid 334.762875 -275.96194)
		(end 334.72374 -275.940774)
		(width 0.088646)
		(layer "F.Cu")
		(net "M_A_CPU0_SA_DQ<7>")
	)
	(arc
		(start 333.951834 -275.848318)
		(mid 333.757414 -275.90035)
		(end 333.56296 -275.848318)
		(width 0.088646)
		(layer "F.Cu")
		(net "M_A_CPU0_SA_DQ<7>")
	)
	(arc
		(start 333.56296 -275.848318)
		(mid 333.472653 -275.810989)
		(end 333.375762 -275.79828)
		(width 0.088646)
		(layer "F.Cu")
		(net "M_A_CPU0_SA_DQ<7>")
	)
	(segment
		(start 320.399918 -304.019712)
		(end 320.115946 -304.019712)
		(width 0.20066)
		(layer "F.Cu")
		(net "M_A_CPU0_SA_DQ<6>")
	)
	(segment
		(start 332.241652 -277.634446)
		(end 331.827886 -278.048212)
		(width 0.088646)
		(layer "F.Cu")
		(net "M_A_CPU0_SA_DQ<6>")
	)
	(segment
		(start 320.790316 -303.629314)
		(end 320.399918 -304.019712)
		(width 0.20066)
		(layer "F.Cu")
		(net "M_A_CPU0_SA_DQ<6>")
	)
	(segment
		(start 317.925958 -304.563272)
		(end 317.925958 -304.847244)
		(width 0.20066)
		(layer "F.Cu")
		(net "M_A_CPU0_SA_DQ<6>")
	)
	(segment
		(start 307.76291 -309.0799)
		(end 307.765196 -309.0799)
		(width 0.101854)
		(layer "F.Cu")
		(net "M_A_CPU0_SA_DQ<6>")
	)
	(segment
		(start 310.630062 -309.64505)
		(end 310.891682 -309.64505)
		(width 0.20066)
		(layer "F.Cu")
		(net "M_A_CPU0_SA_DQ<6>")
	)
	(segment
		(start 330.03998 -282.009596)
		(end 330.03998 -295.342818)
		(width 0.1016)
		(layer "F.Cu")
		(net "M_A_CPU0_SA_DQ<6>")
	)
	(segment
		(start 318.931798 -303.557432)
		(end 318.931798 -303.841404)
		(width 0.20066)
		(layer "F.Cu")
		(net "M_A_CPU0_SA_DQ<6>")
	)
	(segment
		(start 305.443382 -309.51678)
		(end 306.940458 -309.51678)
		(width 0.20066)
		(layer "F.Cu")
		(net "M_A_CPU0_SA_DQ<6>")
	)
	(segment
		(start 331.827886 -278.048212)
		(end 331.629766 -278.048212)
		(width 0.088646)
		(layer "F.Cu")
		(net "M_A_CPU0_SA_DQ<6>")
	)
	(segment
		(start 311.02046 -309.51678)
		(end 312.987182 -309.51678)
		(width 0.20066)
		(layer "F.Cu")
		(net "M_A_CPU0_SA_DQ<6>")
	)
	(segment
		(start 310.457088 -309.232554)
		(end 310.457088 -309.472076)
		(width 0.20066)
		(layer "F.Cu")
		(net "M_A_CPU0_SA_DQ<6>")
	)
	(segment
		(start 330.03998 -295.342818)
		(end 329.178158 -296.20464)
		(width 0.1016)
		(layer "F.Cu")
		(net "M_A_CPU0_SA_DQ<6>")
	)
	(segment
		(start 319.394078 -305.025552)
		(end 319.110106 -305.025552)
		(width 0.20066)
		(layer "F.Cu")
		(net "M_A_CPU0_SA_DQ<6>")
	)
	(segment
		(start 317.925958 -304.847244)
		(end 318.607186 -305.528472)
		(width 0.20066)
		(layer "F.Cu")
		(net "M_A_CPU0_SA_DQ<6>")
	)
	(segment
		(start 318.428878 -304.344324)
		(end 318.144906 -304.344324)
		(width 0.20066)
		(layer "F.Cu")
		(net "M_A_CPU0_SA_DQ<6>")
	)
	(segment
		(start 320.115946 -304.019712)
		(end 319.434718 -303.338484)
		(width 0.20066)
		(layer "F.Cu")
		(net "M_A_CPU0_SA_DQ<6>")
	)
	(segment
		(start 318.607186 -305.528472)
		(end 318.607186 -305.812444)
		(width 0.20066)
		(layer "F.Cu")
		(net "M_A_CPU0_SA_DQ<6>")
	)
	(segment
		(start 332.241652 -277.499572)
		(end 332.241652 -277.634446)
		(width 0.088646)
		(layer "F.Cu")
		(net "M_A_CPU0_SA_DQ<6>")
	)
	(segment
		(start 307.16982 -309.0799)
		(end 307.76291 -309.0799)
		(width 0.20066)
		(layer "F.Cu")
		(net "M_A_CPU0_SA_DQ<6>")
	)
	(segment
		(start 334.89392 -276.582886)
		(end 334.078072 -276.582886)
		(width 0.088646)
		(layer "F.Cu")
		(net "M_A_CPU0_SA_DQ<6>")
	)
	(segment
		(start 310.316118 -309.091584)
		(end 310.457088 -309.232554)
		(width 0.20066)
		(layer "F.Cu")
		(net "M_A_CPU0_SA_DQ<6>")
	)
	(segment
		(start 331.307948 -278.37003)
		(end 330.634086 -279.043892)
		(width 0.1016)
		(layer "F.Cu")
		(net "M_A_CPU0_SA_DQ<6>")
	)
	(segment
		(start 307.77688 -309.091584)
		(end 310.01208 -309.091584)
		(width 0.1016)
		(layer "F.Cu")
		(net "M_A_CPU0_SA_DQ<6>")
	)
	(segment
		(start 307.04282 -309.2069)
		(end 307.16982 -309.0799)
		(width 0.20066)
		(layer "F.Cu")
		(net "M_A_CPU0_SA_DQ<6>")
	)
	(segment
		(start 310.457088 -309.472076)
		(end 310.630062 -309.64505)
		(width 0.20066)
		(layer "F.Cu")
		(net "M_A_CPU0_SA_DQ<6>")
	)
	(segment
		(start 310.01208 -309.091584)
		(end 310.088026 -309.091584)
		(width 0.101854)
		(layer "F.Cu")
		(net "M_A_CPU0_SA_DQ<6>")
	)
	(segment
		(start 331.629766 -278.048212)
		(end 331.307948 -278.37003)
		(width 0.088646)
		(layer "F.Cu")
		(net "M_A_CPU0_SA_DQ<6>")
	)
	(segment
		(start 318.931798 -303.841404)
		(end 319.613026 -304.522632)
		(width 0.20066)
		(layer "F.Cu")
		(net "M_A_CPU0_SA_DQ<6>")
	)
	(segment
		(start 319.110106 -305.025552)
		(end 318.428878 -304.344324)
		(width 0.20066)
		(layer "F.Cu")
		(net "M_A_CPU0_SA_DQ<6>")
	)
	(segment
		(start 307.04282 -309.414418)
		(end 307.04282 -309.2069)
		(width 0.20066)
		(layer "F.Cu")
		(net "M_A_CPU0_SA_DQ<6>")
	)
	(segment
		(start 319.150746 -303.338484)
		(end 318.931798 -303.557432)
		(width 0.20066)
		(layer "F.Cu")
		(net "M_A_CPU0_SA_DQ<6>")
	)
	(segment
		(start 311.020206 -309.516526)
		(end 311.02046 -309.51678)
		(width 0.20066)
		(layer "F.Cu")
		(net "M_A_CPU0_SA_DQ<6>")
	)
	(segment
		(start 319.434718 -303.338484)
		(end 319.150746 -303.338484)
		(width 0.20066)
		(layer "F.Cu")
		(net "M_A_CPU0_SA_DQ<6>")
	)
	(segment
		(start 307.765196 -309.0799)
		(end 307.77688 -309.091584)
		(width 0.101854)
		(layer "F.Cu")
		(net "M_A_CPU0_SA_DQ<6>")
	)
	(segment
		(start 310.088026 -309.091584)
		(end 310.316118 -309.091584)
		(width 0.20066)
		(layer "F.Cu")
		(net "M_A_CPU0_SA_DQ<6>")
	)
	(segment
		(start 320.790316 -302.620426)
		(end 320.790316 -303.629314)
		(width 0.20066)
		(layer "F.Cu")
		(net "M_A_CPU0_SA_DQ<6>")
	)
	(segment
		(start 306.940458 -309.51678)
		(end 307.04282 -309.414418)
		(width 0.20066)
		(layer "F.Cu")
		(net "M_A_CPU0_SA_DQ<6>")
	)
	(segment
		(start 314.90285 -309.51678)
		(end 312.987182 -309.51678)
		(width 0.20066)
		(layer "F.Cu")
		(net "M_A_CPU0_SA_DQ<6>")
	)
	(segment
		(start 322.178426 -301.232316)
		(end 320.790316 -302.620426)
		(width 0.20066)
		(layer "F.Cu")
		(net "M_A_CPU0_SA_DQ<6>")
	)
	(segment
		(start 329.178158 -296.20464)
		(end 324.150482 -301.232316)
		(width 0.20066)
		(layer "F.Cu")
		(net "M_A_CPU0_SA_DQ<6>")
	)
	(segment
		(start 333.003398 -276.737826)
		(end 332.241652 -277.499572)
		(width 0.088646)
		(layer "F.Cu")
		(net "M_A_CPU0_SA_DQ<6>")
	)
	(segment
		(start 324.150482 -301.232316)
		(end 322.178426 -301.232316)
		(width 0.20066)
		(layer "F.Cu")
		(net "M_A_CPU0_SA_DQ<6>")
	)
	(segment
		(start 330.634086 -279.043892)
		(end 330.03998 -282.009596)
		(width 0.1016)
		(layer "F.Cu")
		(net "M_A_CPU0_SA_DQ<6>")
	)
	(segment
		(start 319.613026 -304.806604)
		(end 319.394078 -305.025552)
		(width 0.20066)
		(layer "F.Cu")
		(net "M_A_CPU0_SA_DQ<6>")
	)
	(segment
		(start 318.144906 -304.344324)
		(end 317.925958 -304.563272)
		(width 0.20066)
		(layer "F.Cu")
		(net "M_A_CPU0_SA_DQ<6>")
	)
	(segment
		(start 310.891682 -309.64505)
		(end 311.020206 -309.516526)
		(width 0.20066)
		(layer "F.Cu")
		(net "M_A_CPU0_SA_DQ<6>")
	)
	(segment
		(start 335.725262 -276.986492)
		(end 335.625186 -276.886162)
		(width 0.088646)
		(layer "F.Cu")
		(net "M_A_CPU0_SA_DQ<6>")
	)
	(segment
		(start 319.613026 -304.522632)
		(end 319.613026 -304.806604)
		(width 0.20066)
		(layer "F.Cu")
		(net "M_A_CPU0_SA_DQ<6>")
	)
	(segment
		(start 333.375762 -276.737826)
		(end 333.003398 -276.737826)
		(width 0.088646)
		(layer "F.Cu")
		(net "M_A_CPU0_SA_DQ<6>")
	)
	(segment
		(start 318.607186 -305.812444)
		(end 314.90285 -309.51678)
		(width 0.20066)
		(layer "F.Cu")
		(net "M_A_CPU0_SA_DQ<6>")
	)
	(arc
		(start 335.625186 -276.886162)
		(mid 335.28975 -276.661714)
		(end 334.89392 -276.582886)
		(width 0.088646)
		(layer "F.Cu")
		(net "M_A_CPU0_SA_DQ<6>")
	)
	(arc
		(start 333.718408 -276.639782)
		(mid 333.676803 -276.655371)
		(end 333.63662 -276.674326)
		(width 0.088646)
		(layer "F.Cu")
		(net "M_A_CPU0_SA_DQ<6>")
	)
	(arc
		(start 334.078072 -276.582886)
		(mid 333.896001 -276.597191)
		(end 333.718408 -276.639782)
		(width 0.088646)
		(layer "F.Cu")
		(net "M_A_CPU0_SA_DQ<6>")
	)
	(arc
		(start 333.63662 -276.674326)
		(mid 333.510018 -276.721808)
		(end 333.375762 -276.737826)
		(width 0.088646)
		(layer "F.Cu")
		(net "M_A_CPU0_SA_DQ<6>")
	)
	(segment
		(start 301.967392 -308.666388)
		(end 302.21936 -308.918356)
		(width 0.20066)
		(layer "F.Cu")
		(net "M_A_CPU0_SA_DQ<5>")
	)
	(segment
		(start 331.089508 -278.151844)
		(end 330.354432 -278.88692)
		(width 0.1016)
		(layer "F.Cu")
		(net "M_A_CPU0_SA_DQ<5>")
	)
	(segment
		(start 311.145428 -309.10784)
		(end 310.70423 -308.666642)
		(width 0.20066)
		(layer "F.Cu")
		(net "M_A_CPU0_SA_DQ<5>")
	)
	(segment
		(start 317.2079 -305.845464)
		(end 316.988952 -306.064412)
		(width 0.20066)
		(layer "F.Cu")
		(net "M_A_CPU0_SA_DQ<5>")
	)
	(segment
		(start 302.837596 -308.684168)
		(end 302.837596 -308.421786)
		(width 0.20066)
		(layer "F.Cu")
		(net "M_A_CPU0_SA_DQ<5>")
	)
	(segment
		(start 314.59551 -308.479698)
		(end 314.59551 -308.903116)
		(width 0.20066)
		(layer "F.Cu")
		(net "M_A_CPU0_SA_DQ<5>")
	)
	(segment
		(start 329.73518 -294.742616)
		(end 329.15733 -295.320466)
		(width 0.1016)
		(layer "F.Cu")
		(net "M_A_CPU0_SA_DQ<5>")
	)
	(segment
		(start 331.405484 -277.835868)
		(end 331.089508 -278.151844)
		(width 0.088646)
		(layer "F.Cu")
		(net "M_A_CPU0_SA_DQ<5>")
	)
	(segment
		(start 333.35214 -276.534626)
		(end 333.021432 -276.534626)
		(width 0.088646)
		(layer "F.Cu")
		(net "M_A_CPU0_SA_DQ<5>")
	)
	(segment
		(start 311.91708 -309.10784)
		(end 311.145428 -309.10784)
		(width 0.20066)
		(layer "F.Cu")
		(net "M_A_CPU0_SA_DQ<5>")
	)
	(segment
		(start 321.076066 -300.503082)
		(end 316.754764 -304.824384)
		(width 0.20066)
		(layer "F.Cu")
		(net "M_A_CPU0_SA_DQ<5>")
	)
	(segment
		(start 332.051152 -277.555706)
		(end 331.77099 -277.835868)
		(width 0.088646)
		(layer "F.Cu")
		(net "M_A_CPU0_SA_DQ<5>")
	)
	(segment
		(start 314.097924 -309.102252)
		(end 314.087256 -309.091584)
		(width 0.101854)
		(layer "F.Cu")
		(net "M_A_CPU0_SA_DQ<5>")
	)
	(segment
		(start 311.959244 -309.10784)
		(end 311.91708 -309.10784)
		(width 0.101854)
		(layer "F.Cu")
		(net "M_A_CPU0_SA_DQ<5>")
	)
	(segment
		(start 303.025302 -308.23408)
		(end 304.319178 -308.23408)
		(width 0.20066)
		(layer "F.Cu")
		(net "M_A_CPU0_SA_DQ<5>")
	)
	(segment
		(start 315.967872 -305.611276)
		(end 315.805566 -305.773582)
		(width 0.20066)
		(layer "F.Cu")
		(net "M_A_CPU0_SA_DQ<5>")
	)
	(segment
		(start 331.77099 -277.835868)
		(end 331.405484 -277.835868)
		(width 0.088646)
		(layer "F.Cu")
		(net "M_A_CPU0_SA_DQ<5>")
	)
	(segment
		(start 316.754764 -304.824384)
		(end 316.754764 -305.108356)
		(width 0.20066)
		(layer "F.Cu")
		(net "M_A_CPU0_SA_DQ<5>")
	)
	(segment
		(start 310.70423 -308.666642)
		(end 308.887114 -308.666642)
		(width 0.20066)
		(layer "F.Cu")
		(net "M_A_CPU0_SA_DQ<5>")
	)
	(segment
		(start 304.335942 -308.23408)
		(end 304.343562 -308.2417)
		(width 0.101854)
		(layer "F.Cu")
		(net "M_A_CPU0_SA_DQ<5>")
	)
	(segment
		(start 332.051152 -277.420832)
		(end 332.051152 -277.555706)
		(width 0.088646)
		(layer "F.Cu")
		(net "M_A_CPU0_SA_DQ<5>")
	)
	(segment
		(start 314.593986 -308.911752)
		(end 314.592208 -308.921658)
		(width 0.20066)
		(layer "F.Cu")
		(net "M_A_CPU0_SA_DQ<5>")
	)
	(segment
		(start 330.354432 -278.88692)
		(end 329.73518 -281.9781)
		(width 0.1016)
		(layer "F.Cu")
		(net "M_A_CPU0_SA_DQ<5>")
	)
	(segment
		(start 307.223922 -308.666642)
		(end 308.887114 -308.666642)
		(width 0.20066)
		(layer "F.Cu")
		(net "M_A_CPU0_SA_DQ<5>")
	)
	(segment
		(start 302.21936 -308.918356)
		(end 302.603408 -308.918356)
		(width 0.20066)
		(layer "F.Cu")
		(net "M_A_CPU0_SA_DQ<5>")
	)
	(segment
		(start 315.805566 -307.269642)
		(end 314.59551 -308.479698)
		(width 0.20066)
		(layer "F.Cu")
		(net "M_A_CPU0_SA_DQ<5>")
	)
	(segment
		(start 302.603408 -308.918356)
		(end 302.837596 -308.684168)
		(width 0.20066)
		(layer "F.Cu")
		(net "M_A_CPU0_SA_DQ<5>")
	)
	(segment
		(start 306.58308 -308.2417)
		(end 306.644294 -308.2417)
		(width 0.101854)
		(layer "F.Cu")
		(net "M_A_CPU0_SA_DQ<5>")
	)
	(segment
		(start 323.974714 -300.503082)
		(end 321.076066 -300.503082)
		(width 0.20066)
		(layer "F.Cu")
		(net "M_A_CPU0_SA_DQ<5>")
	)
	(segment
		(start 329.15733 -295.320466)
		(end 323.974714 -300.503082)
		(width 0.20066)
		(layer "F.Cu")
		(net "M_A_CPU0_SA_DQ<5>")
	)
	(segment
		(start 304.319178 -308.23408)
		(end 304.335942 -308.23408)
		(width 0.101854)
		(layer "F.Cu")
		(net "M_A_CPU0_SA_DQ<5>")
	)
	(segment
		(start 329.73518 -281.9781)
		(end 329.73518 -294.742616)
		(width 0.1016)
		(layer "F.Cu")
		(net "M_A_CPU0_SA_DQ<5>")
	)
	(segment
		(start 306.644294 -308.2417)
		(end 306.79898 -308.2417)
		(width 0.20066)
		(layer "F.Cu")
		(net "M_A_CPU0_SA_DQ<5>")
	)
	(segment
		(start 332.899258 -276.572726)
		(end 332.051152 -277.420832)
		(width 0.088646)
		(layer "F.Cu")
		(net "M_A_CPU0_SA_DQ<5>")
	)
	(segment
		(start 302.837596 -308.421786)
		(end 303.025302 -308.23408)
		(width 0.20066)
		(layer "F.Cu")
		(net "M_A_CPU0_SA_DQ<5>")
	)
	(segment
		(start 314.59551 -308.903116)
		(end 314.593986 -308.911752)
		(width 0.20066)
		(layer "F.Cu")
		(net "M_A_CPU0_SA_DQ<5>")
	)
	(segment
		(start 316.251844 -305.611276)
		(end 315.967872 -305.611276)
		(width 0.20066)
		(layer "F.Cu")
		(net "M_A_CPU0_SA_DQ<5>")
	)
	(segment
		(start 301.343314 -308.666642)
		(end 301.967138 -308.666642)
		(width 0.20066)
		(layer "F.Cu")
		(net "M_A_CPU0_SA_DQ<5>")
	)
	(segment
		(start 316.754764 -305.108356)
		(end 317.2079 -305.561492)
		(width 0.20066)
		(layer "F.Cu")
		(net "M_A_CPU0_SA_DQ<5>")
	)
	(segment
		(start 314.592208 -308.921658)
		(end 314.321952 -309.102252)
		(width 0.20066)
		(layer "F.Cu")
		(net "M_A_CPU0_SA_DQ<5>")
	)
	(segment
		(start 314.321952 -309.102252)
		(end 314.15228 -309.102252)
		(width 0.20066)
		(layer "F.Cu")
		(net "M_A_CPU0_SA_DQ<5>")
	)
	(segment
		(start 334.315562 -276.172676)
		(end 334.300068 -276.18817)
		(width 0.088646)
		(layer "F.Cu")
		(net "M_A_CPU0_SA_DQ<5>")
	)
	(segment
		(start 314.087256 -309.091584)
		(end 311.9755 -309.091584)
		(width 0.1016)
		(layer "F.Cu")
		(net "M_A_CPU0_SA_DQ<5>")
	)
	(segment
		(start 304.343562 -308.2417)
		(end 304.37328 -308.2417)
		(width 0.101854)
		(layer "F.Cu")
		(net "M_A_CPU0_SA_DQ<5>")
	)
	(segment
		(start 315.805566 -305.773582)
		(end 315.805566 -307.269642)
		(width 0.20066)
		(layer "F.Cu")
		(net "M_A_CPU0_SA_DQ<5>")
	)
	(segment
		(start 316.988952 -306.064412)
		(end 316.70498 -306.064412)
		(width 0.20066)
		(layer "F.Cu")
		(net "M_A_CPU0_SA_DQ<5>")
	)
	(segment
		(start 304.37328 -308.2417)
		(end 306.58308 -308.2417)
		(width 0.1016)
		(layer "F.Cu")
		(net "M_A_CPU0_SA_DQ<5>")
	)
	(segment
		(start 314.15228 -309.102252)
		(end 314.097924 -309.102252)
		(width 0.101854)
		(layer "F.Cu")
		(net "M_A_CPU0_SA_DQ<5>")
	)
	(segment
		(start 301.967138 -308.666642)
		(end 301.967392 -308.666388)
		(width 0.20066)
		(layer "F.Cu")
		(net "M_A_CPU0_SA_DQ<5>")
	)
	(segment
		(start 316.70498 -306.064412)
		(end 316.251844 -305.611276)
		(width 0.20066)
		(layer "F.Cu")
		(net "M_A_CPU0_SA_DQ<5>")
	)
	(segment
		(start 306.79898 -308.2417)
		(end 307.223922 -308.666642)
		(width 0.20066)
		(layer "F.Cu")
		(net "M_A_CPU0_SA_DQ<5>")
	)
	(segment
		(start 317.2079 -305.561492)
		(end 317.2079 -305.845464)
		(width 0.20066)
		(layer "F.Cu")
		(net "M_A_CPU0_SA_DQ<5>")
	)
	(segment
		(start 311.9755 -309.091584)
		(end 311.959244 -309.10784)
		(width 0.101854)
		(layer "F.Cu")
		(net "M_A_CPU0_SA_DQ<5>")
	)
	(arc
		(start 333.844646 -276.404832)
		(mid 333.802355 -276.418646)
		(end 333.758794 -276.427692)
		(width 0.088646)
		(layer "F.Cu")
		(net "M_A_CPU0_SA_DQ<5>")
	)
	(arc
		(start 333.758794 -276.427692)
		(mid 333.676921 -276.446751)
		(end 333.598774 -276.47773)
		(width 0.088646)
		(layer "F.Cu")
		(net "M_A_CPU0_SA_DQ<5>")
	)
	(arc
		(start 333.021432 -276.534626)
		(mid 332.969859 -276.540233)
		(end 332.920848 -276.557232)
		(width 0.088646)
		(layer "F.Cu")
		(net "M_A_CPU0_SA_DQ<5>")
	)
	(arc
		(start 332.920848 -276.557232)
		(mid 332.909394 -276.564062)
		(end 332.899258 -276.572726)
		(width 0.088646)
		(layer "F.Cu")
		(net "M_A_CPU0_SA_DQ<5>")
	)
	(arc
		(start 334.300068 -276.18817)
		(mid 334.076009 -276.304178)
		(end 333.844646 -276.404832)
		(width 0.088646)
		(layer "F.Cu")
		(net "M_A_CPU0_SA_DQ<5>")
	)
	(arc
		(start 333.598774 -276.47773)
		(mid 333.478684 -276.520166)
		(end 333.35214 -276.534626)
		(width 0.088646)
		(layer "F.Cu")
		(net "M_A_CPU0_SA_DQ<5>")
	)
	(segment
		(start 321.494912 -303.120806)
		(end 321.550284 -302.842676)
		(width 0.20066)
		(layer "F.Cu")
		(net "M_A_CPU0_SA_DQ<4>")
	)
	(segment
		(start 322.884546 -303.000918)
		(end 322.939918 -302.722788)
		(width 0.20066)
		(layer "F.Cu")
		(net "M_A_CPU0_SA_DQ<4>")
	)
	(segment
		(start 331.875384 -278.249126)
		(end 331.903324 -278.249126)
		(width 0.088646)
		(layer "F.Cu")
		(net "M_A_CPU0_SA_DQ<4>")
	)
	(segment
		(start 307.15585 -310.139842)
		(end 307.717952 -310.139842)
		(width 0.20066)
		(layer "F.Cu")
		(net "M_A_CPU0_SA_DQ<4>")
	)
	(segment
		(start 332.439772 -277.570692)
		(end 333.023972 -276.986492)
		(width 0.088646)
		(layer "F.Cu")
		(net "M_A_CPU0_SA_DQ<4>")
	)
	(segment
		(start 306.95773 -309.941722)
		(end 307.15585 -310.139842)
		(width 0.20066)
		(layer "F.Cu")
		(net "M_A_CPU0_SA_DQ<4>")
	)
	(segment
		(start 322.086224 -302.725582)
		(end 322.348606 -303.118012)
		(width 0.20066)
		(layer "F.Cu")
		(net "M_A_CPU0_SA_DQ<4>")
	)
	(segment
		(start 330.34478 -295.588182)
		(end 330.34478 -282.041854)
		(width 0.1016)
		(layer "F.Cu")
		(net "M_A_CPU0_SA_DQ<4>")
	)
	(segment
		(start 307.944774 -310.366664)
		(end 308.887114 -310.366664)
		(width 0.20066)
		(layer "F.Cu")
		(net "M_A_CPU0_SA_DQ<4>")
	)
	(segment
		(start 329.567032 -296.721022)
		(end 330.093828 -296.194226)
		(width 0.1016)
		(layer "F.Cu")
		(net "M_A_CPU0_SA_DQ<4>")
	)
	(segment
		(start 315.152532 -310.172354)
		(end 321.195192 -304.129694)
		(width 0.20066)
		(layer "F.Cu")
		(net "M_A_CPU0_SA_DQ<4>")
	)
	(segment
		(start 332.439772 -277.712678)
		(end 332.439772 -277.570692)
		(width 0.088646)
		(layer "F.Cu")
		(net "M_A_CPU0_SA_DQ<4>")
	)
	(segment
		(start 322.939918 -302.722788)
		(end 322.677536 -302.330358)
		(width 0.20066)
		(layer "F.Cu")
		(net "M_A_CPU0_SA_DQ<4>")
	)
	(segment
		(start 301.967138 -310.366664)
		(end 301.967392 -310.36641)
		(width 0.20066)
		(layer "F.Cu")
		(net "M_A_CPU0_SA_DQ<4>")
	)
	(segment
		(start 311.91708 -309.927244)
		(end 311.966102 -309.927244)
		(width 0.101854)
		(layer "F.Cu")
		(net "M_A_CPU0_SA_DQ<4>")
	)
	(segment
		(start 302.837596 -310.38419)
		(end 302.837596 -310.121808)
		(width 0.20066)
		(layer "F.Cu")
		(net "M_A_CPU0_SA_DQ<4>")
	)
	(segment
		(start 314.044584 -309.941722)
		(end 314.060332 -309.925974)
		(width 0.101854)
		(layer "F.Cu")
		(net "M_A_CPU0_SA_DQ<4>")
	)
	(segment
		(start 304.330862 -309.902606)
		(end 304.369978 -309.941722)
		(width 0.101854)
		(layer "F.Cu")
		(net "M_A_CPU0_SA_DQ<4>")
	)
	(segment
		(start 306.55768 -309.941722)
		(end 306.644294 -309.941722)
		(width 0.101854)
		(layer "F.Cu")
		(net "M_A_CPU0_SA_DQ<4>")
	)
	(segment
		(start 304.369978 -309.941722)
		(end 304.39868 -309.941722)
		(width 0.101854)
		(layer "F.Cu")
		(net "M_A_CPU0_SA_DQ<4>")
	)
	(segment
		(start 321.195192 -304.129694)
		(end 321.701922 -303.791112)
		(width 0.20066)
		(layer "F.Cu")
		(net "M_A_CPU0_SA_DQ<4>")
	)
	(segment
		(start 308.887114 -310.366664)
		(end 309.715154 -310.366664)
		(width 0.20066)
		(layer "F.Cu")
		(net "M_A_CPU0_SA_DQ<4>")
	)
	(segment
		(start 314.060332 -309.925974)
		(end 314.12688 -309.925974)
		(width 0.101854)
		(layer "F.Cu")
		(net "M_A_CPU0_SA_DQ<4>")
	)
	(segment
		(start 330.093828 -296.194226)
		(end 330.34478 -295.588182)
		(width 0.1016)
		(layer "F.Cu")
		(net "M_A_CPU0_SA_DQ<4>")
	)
	(segment
		(start 330.34478 -282.041854)
		(end 330.9112 -279.21331)
		(width 0.1016)
		(layer "F.Cu")
		(net "M_A_CPU0_SA_DQ<4>")
	)
	(segment
		(start 323.53123 -302.327564)
		(end 323.809106 -302.382936)
		(width 0.20066)
		(layer "F.Cu")
		(net "M_A_CPU0_SA_DQ<4>")
	)
	(segment
		(start 311.98058 -309.941722)
		(end 314.044584 -309.941722)
		(width 0.1016)
		(layer "F.Cu")
		(net "M_A_CPU0_SA_DQ<4>")
	)
	(segment
		(start 303.056798 -309.902606)
		(end 304.319178 -309.902606)
		(width 0.20066)
		(layer "F.Cu")
		(net "M_A_CPU0_SA_DQ<4>")
	)
	(segment
		(start 310.862472 -310.115966)
		(end 311.418224 -309.927244)
		(width 0.20066)
		(layer "F.Cu")
		(net "M_A_CPU0_SA_DQ<4>")
	)
	(segment
		(start 322.732908 -302.052228)
		(end 322.990972 -301.879762)
		(width 0.20066)
		(layer "F.Cu")
		(net "M_A_CPU0_SA_DQ<4>")
	)
	(segment
		(start 301.343314 -310.366664)
		(end 301.967138 -310.366664)
		(width 0.20066)
		(layer "F.Cu")
		(net "M_A_CPU0_SA_DQ<4>")
	)
	(segment
		(start 314.12688 -309.925974)
		(end 314.596526 -309.925974)
		(width 0.20066)
		(layer "F.Cu")
		(net "M_A_CPU0_SA_DQ<4>")
	)
	(segment
		(start 302.603408 -310.618378)
		(end 302.837596 -310.38419)
		(width 0.20066)
		(layer "F.Cu")
		(net "M_A_CPU0_SA_DQ<4>")
	)
	(segment
		(start 301.967392 -310.36641)
		(end 302.21936 -310.618378)
		(width 0.20066)
		(layer "F.Cu")
		(net "M_A_CPU0_SA_DQ<4>")
	)
	(segment
		(start 322.348606 -303.118012)
		(end 322.626482 -303.173384)
		(width 0.20066)
		(layer "F.Cu")
		(net "M_A_CPU0_SA_DQ<4>")
	)
	(segment
		(start 321.808348 -302.67021)
		(end 322.086224 -302.725582)
		(width 0.20066)
		(layer "F.Cu")
		(net "M_A_CPU0_SA_DQ<4>")
	)
	(segment
		(start 323.809106 -302.382936)
		(end 324.09892 -302.189134)
		(width 0.20066)
		(layer "F.Cu")
		(net "M_A_CPU0_SA_DQ<4>")
	)
	(segment
		(start 321.757294 -303.513236)
		(end 321.494912 -303.120806)
		(width 0.20066)
		(layer "F.Cu")
		(net "M_A_CPU0_SA_DQ<4>")
	)
	(segment
		(start 331.903324 -278.249126)
		(end 332.439772 -277.712678)
		(width 0.088646)
		(layer "F.Cu")
		(net "M_A_CPU0_SA_DQ<4>")
	)
	(segment
		(start 311.418224 -309.927244)
		(end 311.91708 -309.927244)
		(width 0.20066)
		(layer "F.Cu")
		(net "M_A_CPU0_SA_DQ<4>")
	)
	(segment
		(start 304.39868 -309.941722)
		(end 306.55768 -309.941722)
		(width 0.1016)
		(layer "F.Cu")
		(net "M_A_CPU0_SA_DQ<4>")
	)
	(segment
		(start 309.715154 -310.366664)
		(end 310.862472 -310.115966)
		(width 0.20066)
		(layer "F.Cu")
		(net "M_A_CPU0_SA_DQ<4>")
	)
	(segment
		(start 322.677536 -302.330358)
		(end 322.732908 -302.052228)
		(width 0.20066)
		(layer "F.Cu")
		(net "M_A_CPU0_SA_DQ<4>")
	)
	(segment
		(start 322.990972 -301.879762)
		(end 323.268848 -301.935134)
		(width 0.20066)
		(layer "F.Cu")
		(net "M_A_CPU0_SA_DQ<4>")
	)
	(segment
		(start 321.550284 -302.842676)
		(end 321.808348 -302.67021)
		(width 0.20066)
		(layer "F.Cu")
		(net "M_A_CPU0_SA_DQ<4>")
	)
	(segment
		(start 307.717952 -310.139842)
		(end 307.944774 -310.366664)
		(width 0.20066)
		(layer "F.Cu")
		(net "M_A_CPU0_SA_DQ<4>")
	)
	(segment
		(start 302.837596 -310.121808)
		(end 303.056798 -309.902606)
		(width 0.20066)
		(layer "F.Cu")
		(net "M_A_CPU0_SA_DQ<4>")
	)
	(segment
		(start 306.644294 -309.941722)
		(end 306.95773 -309.941722)
		(width 0.20066)
		(layer "F.Cu")
		(net "M_A_CPU0_SA_DQ<4>")
	)
	(segment
		(start 321.701922 -303.791112)
		(end 321.757294 -303.513236)
		(width 0.20066)
		(layer "F.Cu")
		(net "M_A_CPU0_SA_DQ<4>")
	)
	(segment
		(start 331.531214 -278.593296)
		(end 331.875384 -278.249126)
		(width 0.088646)
		(layer "F.Cu")
		(net "M_A_CPU0_SA_DQ<4>")
	)
	(segment
		(start 311.966102 -309.927244)
		(end 311.98058 -309.941722)
		(width 0.101854)
		(layer "F.Cu")
		(net "M_A_CPU0_SA_DQ<4>")
	)
	(segment
		(start 324.09892 -302.189134)
		(end 329.567032 -296.721022)
		(width 0.20066)
		(layer "F.Cu")
		(net "M_A_CPU0_SA_DQ<4>")
	)
	(segment
		(start 314.596526 -309.925974)
		(end 314.842906 -310.172354)
		(width 0.20066)
		(layer "F.Cu")
		(net "M_A_CPU0_SA_DQ<4>")
	)
	(segment
		(start 323.268848 -301.935134)
		(end 323.53123 -302.327564)
		(width 0.20066)
		(layer "F.Cu")
		(net "M_A_CPU0_SA_DQ<4>")
	)
	(segment
		(start 333.023972 -276.986492)
		(end 333.845662 -276.986492)
		(width 0.088646)
		(layer "F.Cu")
		(net "M_A_CPU0_SA_DQ<4>")
	)
	(segment
		(start 322.626482 -303.173384)
		(end 322.884546 -303.000918)
		(width 0.20066)
		(layer "F.Cu")
		(net "M_A_CPU0_SA_DQ<4>")
	)
	(segment
		(start 304.319178 -309.902606)
		(end 304.330862 -309.902606)
		(width 0.101854)
		(layer "F.Cu")
		(net "M_A_CPU0_SA_DQ<4>")
	)
	(segment
		(start 314.842906 -310.172354)
		(end 315.152532 -310.172354)
		(width 0.20066)
		(layer "F.Cu")
		(net "M_A_CPU0_SA_DQ<4>")
	)
	(segment
		(start 302.21936 -310.618378)
		(end 302.603408 -310.618378)
		(width 0.20066)
		(layer "F.Cu")
		(net "M_A_CPU0_SA_DQ<4>")
	)
	(segment
		(start 330.9112 -279.21331)
		(end 331.531214 -278.593296)
		(width 0.1016)
		(layer "F.Cu")
		(net "M_A_CPU0_SA_DQ<4>")
	)
	(segment
		(start 333.138272 -279.086056)
		(end 333.489554 -279.086056)
		(width 0.088646)
		(layer "F.Cu")
		(net "M_A_CPU0_SA_DQ<3>")
	)
	(segment
		(start 319.82537 -309.348124)
		(end 320.109342 -309.348124)
		(width 0.20066)
		(layer "F.Cu")
		(net "M_A_CPU0_SA_DQ<3>")
	)
	(segment
		(start 321.717416 -307.653182)
		(end 321.91833 -307.452268)
		(width 0.20066)
		(layer "F.Cu")
		(net "M_A_CPU0_SA_DQ<3>")
	)
	(segment
		(start 316.067694 -313.381136)
		(end 316.361064 -313.185302)
		(width 0.20066)
		(layer "F.Cu")
		(net "M_A_CPU0_SA_DQ<3>")
	)
	(segment
		(start 321.116198 -308.3433)
		(end 321.212972 -308.440074)
		(width 0.20066)
		(layer "F.Cu")
		(net "M_A_CPU0_SA_DQ<3>")
	)
	(segment
		(start 320.832226 -308.3433)
		(end 321.116198 -308.3433)
		(width 0.20066)
		(layer "F.Cu")
		(net "M_A_CPU0_SA_DQ<3>")
	)
	(segment
		(start 317.81369 -311.359804)
		(end 318.097662 -311.359804)
		(width 0.20066)
		(layer "F.Cu")
		(net "M_A_CPU0_SA_DQ<3>")
	)
	(segment
		(start 331.86878 -282.453588)
		(end 332.365604 -279.970484)
		(width 0.1016)
		(layer "F.Cu")
		(net "M_A_CPU0_SA_DQ<3>")
	)
	(segment
		(start 321.715892 -308.221126)
		(end 321.715892 -307.937154)
		(width 0.20066)
		(layer "F.Cu")
		(net "M_A_CPU0_SA_DQ<3>")
	)
	(segment
		(start 317.692532 -311.960514)
		(end 317.594742 -311.862724)
		(width 0.20066)
		(layer "F.Cu")
		(net "M_A_CPU0_SA_DQ<3>")
	)
	(segment
		(start 317.594742 -311.578752)
		(end 317.81369 -311.359804)
		(width 0.20066)
		(layer "F.Cu")
		(net "M_A_CPU0_SA_DQ<3>")
	)
	(segment
		(start 334.03286 -278.938736)
		(end 334.043274 -278.93264)
		(width 0.088646)
		(layer "F.Cu")
		(net "M_A_CPU0_SA_DQ<3>")
	)
	(segment
		(start 332.944978 -279.27935)
		(end 333.138272 -279.086056)
		(width 0.088646)
		(layer "F.Cu")
		(net "M_A_CPU0_SA_DQ<3>")
	)
	(segment
		(start 331.86878 -297.034204)
		(end 331.86878 -282.453588)
		(width 0.1016)
		(layer "F.Cu")
		(net "M_A_CPU0_SA_DQ<3>")
	)
	(segment
		(start 320.710052 -308.942994)
		(end 320.613278 -308.84622)
		(width 0.20066)
		(layer "F.Cu")
		(net "M_A_CPU0_SA_DQ<3>")
	)
	(segment
		(start 331.137768 -298.79925)
		(end 331.247496 -298.689522)
		(width 0.1016)
		(layer "F.Cu")
		(net "M_A_CPU0_SA_DQ<3>")
	)
	(segment
		(start 320.207132 -309.445914)
		(end 320.491104 -309.445914)
		(width 0.20066)
		(layer "F.Cu")
		(net "M_A_CPU0_SA_DQ<3>")
	)
	(segment
		(start 307.124862 -313.766708)
		(end 307.549804 -314.19165)
		(width 0.20066)
		(layer "F.Cu")
		(net "M_A_CPU0_SA_DQ<3>")
	)
	(segment
		(start 316.447678 -312.748168)
		(end 316.777116 -312.52795)
		(width 0.20066)
		(layer "F.Cu")
		(net "M_A_CPU0_SA_DQ<3>")
	)
	(segment
		(start 318.600582 -310.572912)
		(end 318.81953 -310.353964)
		(width 0.20066)
		(layer "F.Cu")
		(net "M_A_CPU0_SA_DQ<3>")
	)
	(segment
		(start 332.365604 -279.970484)
		(end 332.67523 -279.660858)
		(width 0.1016)
		(layer "F.Cu")
		(net "M_A_CPU0_SA_DQ<3>")
	)
	(segment
		(start 312.021728 -314.150502)
		(end 312.405522 -313.766708)
		(width 0.20066)
		(layer "F.Cu")
		(net "M_A_CPU0_SA_DQ<3>")
	)
	(segment
		(start 321.715892 -307.937154)
		(end 321.717416 -307.93563)
		(width 0.20066)
		(layer "F.Cu")
		(net "M_A_CPU0_SA_DQ<3>")
	)
	(segment
		(start 310.04256 -314.199524)
		(end 310.088026 -314.199524)
		(width 0.101854)
		(layer "F.Cu")
		(net "M_A_CPU0_SA_DQ<3>")
	)
	(segment
		(start 322.721732 -307.215286)
		(end 322.721732 -306.931314)
		(width 0.20066)
		(layer "F.Cu")
		(net "M_A_CPU0_SA_DQ<3>")
	)
	(segment
		(start 320.613278 -308.84622)
		(end 320.613278 -308.562248)
		(width 0.20066)
		(layer "F.Cu")
		(net "M_A_CPU0_SA_DQ<3>")
	)
	(segment
		(start 310.413146 -314.199524)
		(end 310.911748 -313.700922)
		(width 0.20066)
		(layer "F.Cu")
		(net "M_A_CPU0_SA_DQ<3>")
	)
	(segment
		(start 331.247496 -298.689522)
		(end 331.247496 -298.534582)
		(width 0.1016)
		(layer "F.Cu")
		(net "M_A_CPU0_SA_DQ<3>")
	)
	(segment
		(start 311.665874 -314.150502)
		(end 312.021728 -314.150502)
		(width 0.20066)
		(layer "F.Cu")
		(net "M_A_CPU0_SA_DQ<3>")
	)
	(segment
		(start 307.76291 -314.19165)
		(end 307.82768 -314.19165)
		(width 0.101854)
		(layer "F.Cu")
		(net "M_A_CPU0_SA_DQ<3>")
	)
	(segment
		(start 316.777116 -312.52795)
		(end 317.21425 -312.614818)
		(width 0.20066)
		(layer "F.Cu")
		(net "M_A_CPU0_SA_DQ<3>")
	)
	(segment
		(start 321.496944 -308.440074)
		(end 321.715892 -308.221126)
		(width 0.20066)
		(layer "F.Cu")
		(net "M_A_CPU0_SA_DQ<3>")
	)
	(segment
		(start 310.01208 -314.19165)
		(end 310.034686 -314.19165)
		(width 0.101854)
		(layer "F.Cu")
		(net "M_A_CPU0_SA_DQ<3>")
	)
	(segment
		(start 310.034686 -314.19165)
		(end 310.04256 -314.199524)
		(width 0.101854)
		(layer "F.Cu")
		(net "M_A_CPU0_SA_DQ<3>")
	)
	(segment
		(start 318.698372 -310.954674)
		(end 318.600582 -310.856884)
		(width 0.20066)
		(layer "F.Cu")
		(net "M_A_CPU0_SA_DQ<3>")
	)
	(segment
		(start 319.201292 -310.451754)
		(end 319.485264 -310.451754)
		(width 0.20066)
		(layer "F.Cu")
		(net "M_A_CPU0_SA_DQ<3>")
	)
	(segment
		(start 313.41187 -313.766708)
		(end 313.633104 -313.987942)
		(width 0.20066)
		(layer "F.Cu")
		(net "M_A_CPU0_SA_DQ<3>")
	)
	(segment
		(start 318.097662 -311.359804)
		(end 318.195452 -311.457594)
		(width 0.20066)
		(layer "F.Cu")
		(net "M_A_CPU0_SA_DQ<3>")
	)
	(segment
		(start 322.48475 -307.452268)
		(end 322.721732 -307.215286)
		(width 0.20066)
		(layer "F.Cu")
		(net "M_A_CPU0_SA_DQ<3>")
	)
	(segment
		(start 318.81953 -310.353964)
		(end 319.103502 -310.353964)
		(width 0.20066)
		(layer "F.Cu")
		(net "M_A_CPU0_SA_DQ<3>")
	)
	(segment
		(start 318.479424 -311.457594)
		(end 318.698372 -311.238646)
		(width 0.20066)
		(layer "F.Cu")
		(net "M_A_CPU0_SA_DQ<3>")
	)
	(segment
		(start 318.195452 -311.457594)
		(end 318.479424 -311.457594)
		(width 0.20066)
		(layer "F.Cu")
		(net "M_A_CPU0_SA_DQ<3>")
	)
	(segment
		(start 305.443382 -313.766708)
		(end 307.124862 -313.766708)
		(width 0.20066)
		(layer "F.Cu")
		(net "M_A_CPU0_SA_DQ<3>")
	)
	(segment
		(start 335.035652 -278.881078)
		(end 335.269332 -278.647398)
		(width 0.088646)
		(layer "F.Cu")
		(net "M_A_CPU0_SA_DQ<3>")
	)
	(segment
		(start 322.721732 -306.931314)
		(end 323.224652 -306.428394)
		(width 0.20066)
		(layer "F.Cu")
		(net "M_A_CPU0_SA_DQ<3>")
	)
	(segment
		(start 321.212972 -308.440074)
		(end 321.496944 -308.440074)
		(width 0.20066)
		(layer "F.Cu")
		(net "M_A_CPU0_SA_DQ<3>")
	)
	(segment
		(start 319.704212 -310.232806)
		(end 319.704212 -309.948834)
		(width 0.20066)
		(layer "F.Cu")
		(net "M_A_CPU0_SA_DQ<3>")
	)
	(segment
		(start 335.349088 -278.614378)
		(end 335.725262 -278.614378)
		(width 0.088646)
		(layer "F.Cu")
		(net "M_A_CPU0_SA_DQ<3>")
	)
	(segment
		(start 314.917582 -313.857386)
		(end 316.067694 -313.381136)
		(width 0.20066)
		(layer "F.Cu")
		(net "M_A_CPU0_SA_DQ<3>")
	)
	(segment
		(start 317.594742 -311.862724)
		(end 317.594742 -311.578752)
		(width 0.20066)
		(layer "F.Cu")
		(net "M_A_CPU0_SA_DQ<3>")
	)
	(segment
		(start 314.602622 -313.987942)
		(end 314.917582 -313.857386)
		(width 0.20066)
		(layer "F.Cu")
		(net "M_A_CPU0_SA_DQ<3>")
	)
	(segment
		(start 307.82768 -314.19165)
		(end 310.01208 -314.19165)
		(width 0.1016)
		(layer "F.Cu")
		(net "M_A_CPU0_SA_DQ<3>")
	)
	(segment
		(start 332.67523 -279.660858)
		(end 332.80731 -279.528778)
		(width 0.088646)
		(layer "F.Cu")
		(net "M_A_CPU0_SA_DQ<3>")
	)
	(segment
		(start 323.508624 -306.428394)
		(end 331.137768 -298.79925)
		(width 0.20066)
		(layer "F.Cu")
		(net "M_A_CPU0_SA_DQ<3>")
	)
	(segment
		(start 311.216294 -313.700922)
		(end 311.665874 -314.150502)
		(width 0.20066)
		(layer "F.Cu")
		(net "M_A_CPU0_SA_DQ<3>")
	)
	(segment
		(start 317.21425 -312.614818)
		(end 317.539624 -312.397394)
		(width 0.20066)
		(layer "F.Cu")
		(net "M_A_CPU0_SA_DQ<3>")
	)
	(segment
		(start 320.109342 -309.348124)
		(end 320.207132 -309.445914)
		(width 0.20066)
		(layer "F.Cu")
		(net "M_A_CPU0_SA_DQ<3>")
	)
	(segment
		(start 317.539624 -312.397394)
		(end 317.692532 -312.244486)
		(width 0.20066)
		(layer "F.Cu")
		(net "M_A_CPU0_SA_DQ<3>")
	)
	(segment
		(start 310.911748 -313.700922)
		(end 311.216294 -313.700922)
		(width 0.20066)
		(layer "F.Cu")
		(net "M_A_CPU0_SA_DQ<3>")
	)
	(segment
		(start 319.704212 -309.948834)
		(end 319.606422 -309.851044)
		(width 0.20066)
		(layer "F.Cu")
		(net "M_A_CPU0_SA_DQ<3>")
	)
	(segment
		(start 320.710052 -309.226966)
		(end 320.710052 -308.942994)
		(width 0.20066)
		(layer "F.Cu")
		(net "M_A_CPU0_SA_DQ<3>")
	)
	(segment
		(start 319.606422 -309.851044)
		(end 319.606422 -309.567072)
		(width 0.20066)
		(layer "F.Cu")
		(net "M_A_CPU0_SA_DQ<3>")
	)
	(segment
		(start 320.491104 -309.445914)
		(end 320.710052 -309.226966)
		(width 0.20066)
		(layer "F.Cu")
		(net "M_A_CPU0_SA_DQ<3>")
	)
	(segment
		(start 321.91833 -307.452268)
		(end 322.48475 -307.452268)
		(width 0.20066)
		(layer "F.Cu")
		(net "M_A_CPU0_SA_DQ<3>")
	)
	(segment
		(start 316.361064 -313.185302)
		(end 316.447678 -312.748168)
		(width 0.20066)
		(layer "F.Cu")
		(net "M_A_CPU0_SA_DQ<3>")
	)
	(segment
		(start 318.600582 -310.856884)
		(end 318.600582 -310.572912)
		(width 0.20066)
		(layer "F.Cu")
		(net "M_A_CPU0_SA_DQ<3>")
	)
	(segment
		(start 317.692532 -312.244486)
		(end 317.692532 -311.960514)
		(width 0.20066)
		(layer "F.Cu")
		(net "M_A_CPU0_SA_DQ<3>")
	)
	(segment
		(start 319.103502 -310.353964)
		(end 319.201292 -310.451754)
		(width 0.20066)
		(layer "F.Cu")
		(net "M_A_CPU0_SA_DQ<3>")
	)
	(segment
		(start 310.088026 -314.199524)
		(end 310.413146 -314.199524)
		(width 0.20066)
		(layer "F.Cu")
		(net "M_A_CPU0_SA_DQ<3>")
	)
	(segment
		(start 320.613278 -308.562248)
		(end 320.832226 -308.3433)
		(width 0.20066)
		(layer "F.Cu")
		(net "M_A_CPU0_SA_DQ<3>")
	)
	(segment
		(start 321.717416 -307.93563)
		(end 321.717416 -307.653182)
		(width 0.20066)
		(layer "F.Cu")
		(net "M_A_CPU0_SA_DQ<3>")
	)
	(segment
		(start 312.405522 -313.766708)
		(end 312.987182 -313.766708)
		(width 0.20066)
		(layer "F.Cu")
		(net "M_A_CPU0_SA_DQ<3>")
	)
	(segment
		(start 307.549804 -314.19165)
		(end 307.76291 -314.19165)
		(width 0.20066)
		(layer "F.Cu")
		(net "M_A_CPU0_SA_DQ<3>")
	)
	(segment
		(start 319.485264 -310.451754)
		(end 319.704212 -310.232806)
		(width 0.20066)
		(layer "F.Cu")
		(net "M_A_CPU0_SA_DQ<3>")
	)
	(segment
		(start 331.247496 -298.534582)
		(end 331.86878 -297.034204)
		(width 0.1016)
		(layer "F.Cu")
		(net "M_A_CPU0_SA_DQ<3>")
	)
	(segment
		(start 313.633104 -313.987942)
		(end 314.602622 -313.987942)
		(width 0.20066)
		(layer "F.Cu")
		(net "M_A_CPU0_SA_DQ<3>")
	)
	(segment
		(start 323.224652 -306.428394)
		(end 323.508624 -306.428394)
		(width 0.20066)
		(layer "F.Cu")
		(net "M_A_CPU0_SA_DQ<3>")
	)
	(segment
		(start 312.987182 -313.766708)
		(end 313.41187 -313.766708)
		(width 0.20066)
		(layer "F.Cu")
		(net "M_A_CPU0_SA_DQ<3>")
	)
	(segment
		(start 319.606422 -309.567072)
		(end 319.82537 -309.348124)
		(width 0.20066)
		(layer "F.Cu")
		(net "M_A_CPU0_SA_DQ<3>")
	)
	(segment
		(start 318.698372 -311.238646)
		(end 318.698372 -310.954674)
		(width 0.20066)
		(layer "F.Cu")
		(net "M_A_CPU0_SA_DQ<3>")
	)
	(arc
		(start 332.876144 -279.404318)
		(mid 332.901701 -279.336954)
		(end 332.944978 -279.27935)
		(width 0.088646)
		(layer "F.Cu")
		(net "M_A_CPU0_SA_DQ<3>")
	)
	(arc
		(start 333.489554 -279.086056)
		(mid 333.77102 -279.048579)
		(end 334.03286 -278.938736)
		(width 0.088646)
		(layer "F.Cu")
		(net "M_A_CPU0_SA_DQ<3>")
	)
	(arc
		(start 334.043274 -278.93264)
		(mid 334.321706 -278.862794)
		(end 334.598518 -278.938736)
		(width 0.088646)
		(layer "F.Cu")
		(net "M_A_CPU0_SA_DQ<3>")
	)
	(arc
		(start 332.80731 -279.528778)
		(mid 332.850531 -279.471415)
		(end 332.876144 -279.404318)
		(width 0.088646)
		(layer "F.Cu")
		(net "M_A_CPU0_SA_DQ<3>")
	)
	(arc
		(start 335.269332 -278.647398)
		(mid 335.305924 -278.622948)
		(end 335.349088 -278.614378)
		(width 0.088646)
		(layer "F.Cu")
		(net "M_A_CPU0_SA_DQ<3>")
	)
	(arc
		(start 334.598518 -278.938736)
		(mid 334.826901 -278.984161)
		(end 335.035652 -278.881078)
		(width 0.088646)
		(layer "F.Cu")
		(net "M_A_CPU0_SA_DQ<3>")
	)
	(segment
		(start 330.86929 -265.138662)
		(end 330.86929 -265.486134)
		(width 0.1016)
		(layer "F.Cu")
		(net "M_A_CPU0_SA_DQ<31>")
	)
	(segment
		(start 305.443382 -279.766776)
		(end 307.128672 -279.766776)
		(width 0.20066)
		(layer "F.Cu")
		(net "M_A_CPU0_SA_DQ<31>")
	)
	(segment
		(start 332.682088 -264.89025)
		(end 332.391766 -264.599928)
		(width 0.088646)
		(layer "F.Cu")
		(net "M_A_CPU0_SA_DQ<31>")
	)
	(segment
		(start 334.046322 -265.023854)
		(end 333.923894 -264.901426)
		(width 0.088646)
		(layer "F.Cu")
		(net "M_A_CPU0_SA_DQ<31>")
	)
	(segment
		(start 334.785716 -265.592306)
		(end 334.785716 -265.347958)
		(width 0.088646)
		(layer "F.Cu")
		(net "M_A_CPU0_SA_DQ<31>")
	)
	(segment
		(start 333.923894 -264.901426)
		(end 333.76489 -264.901426)
		(width 0.088646)
		(layer "F.Cu")
		(net "M_A_CPU0_SA_DQ<31>")
	)
	(segment
		(start 316.71641 -280.039826)
		(end 316.606174 -280.150062)
		(width 0.20066)
		(layer "F.Cu")
		(net "M_A_CPU0_SA_DQ<31>")
	)
	(segment
		(start 309.828184 -280.191718)
		(end 309.855616 -280.197306)
		(width 0.1016)
		(layer "F.Cu")
		(net "M_A_CPU0_SA_DQ<31>")
	)
	(segment
		(start 317.291974 -279.70861)
		(end 316.826646 -279.70861)
		(width 0.20066)
		(layer "F.Cu")
		(net "M_A_CPU0_SA_DQ<31>")
	)
	(segment
		(start 334.431894 -265.358626)
		(end 334.355694 -265.434826)
		(width 0.088646)
		(layer "F.Cu")
		(net "M_A_CPU0_SA_DQ<31>")
	)
	(segment
		(start 313.864498 -279.766776)
		(end 312.987182 -279.766776)
		(width 0.20066)
		(layer "F.Cu")
		(net "M_A_CPU0_SA_DQ<31>")
	)
	(segment
		(start 315.34481 -280.039826)
		(end 315.234574 -280.150062)
		(width 0.20066)
		(layer "F.Cu")
		(net "M_A_CPU0_SA_DQ<31>")
	)
	(segment
		(start 314.588652 -280.150062)
		(end 314.367926 -279.929336)
		(width 0.20066)
		(layer "F.Cu")
		(net "M_A_CPU0_SA_DQ<31>")
	)
	(segment
		(start 331.879956 -264.772902)
		(end 331.879956 -264.89025)
		(width 0.088646)
		(layer "F.Cu")
		(net "M_A_CPU0_SA_DQ<31>")
	)
	(segment
		(start 317.977774 -280.150062)
		(end 317.512446 -280.150062)
		(width 0.20066)
		(layer "F.Cu")
		(net "M_A_CPU0_SA_DQ<31>")
	)
	(segment
		(start 334.355694 -265.434826)
		(end 334.203294 -265.434826)
		(width 0.088646)
		(layer "F.Cu")
		(net "M_A_CPU0_SA_DQ<31>")
	)
	(segment
		(start 331.117956 -265.594592)
		(end 331.219556 -265.696192)
		(width 0.1016)
		(layer "F.Cu")
		(net "M_A_CPU0_SA_DQ<31>")
	)
	(segment
		(start 307.25491 -280.105866)
		(end 307.357018 -280.207974)
		(width 0.20066)
		(layer "F.Cu")
		(net "M_A_CPU0_SA_DQ<31>")
	)
	(segment
		(start 333.616808 -265.107928)
		(end 333.53883 -265.185906)
		(width 0.088646)
		(layer "F.Cu")
		(net "M_A_CPU0_SA_DQ<31>")
	)
	(segment
		(start 321.28587 -278.55291)
		(end 321.28587 -278.196548)
		(width 0.1016)
		(layer "F.Cu")
		(net "M_A_CPU0_SA_DQ<31>")
	)
	(segment
		(start 333.616808 -265.049508)
		(end 333.616808 -265.107928)
		(width 0.088646)
		(layer "F.Cu")
		(net "M_A_CPU0_SA_DQ<31>")
	)
	(segment
		(start 307.128672 -279.766776)
		(end 307.128926 -279.766522)
		(width 0.20066)
		(layer "F.Cu")
		(net "M_A_CPU0_SA_DQ<31>")
	)
	(segment
		(start 334.772508 -264.987532)
		(end 334.631792 -264.987532)
		(width 0.088646)
		(layer "F.Cu")
		(net "M_A_CPU0_SA_DQ<31>")
	)
	(segment
		(start 310.961532 -279.47112)
		(end 311.736232 -279.47112)
		(width 0.20066)
		(layer "F.Cu")
		(net "M_A_CPU0_SA_DQ<31>")
	)
	(segment
		(start 334.864456 -265.269218)
		(end 334.864456 -265.07948)
		(width 0.088646)
		(layer "F.Cu")
		(net "M_A_CPU0_SA_DQ<31>")
	)
	(segment
		(start 331.778356 -264.99185)
		(end 331.016102 -264.99185)
		(width 0.1016)
		(layer "F.Cu")
		(net "M_A_CPU0_SA_DQ<31>")
	)
	(segment
		(start 334.631792 -264.987532)
		(end 334.431894 -265.18743)
		(width 0.088646)
		(layer "F.Cu")
		(net "M_A_CPU0_SA_DQ<31>")
	)
	(segment
		(start 320.699892 -278.560022)
		(end 320.413126 -278.846788)
		(width 0.1016)
		(layer "F.Cu")
		(net "M_A_CPU0_SA_DQ<31>")
	)
	(segment
		(start 307.128926 -279.766522)
		(end 307.25491 -279.892506)
		(width 0.20066)
		(layer "F.Cu")
		(net "M_A_CPU0_SA_DQ<31>")
	)
	(segment
		(start 309.855616 -280.197306)
		(end 310.088026 -280.197306)
		(width 0.101854)
		(layer "F.Cu")
		(net "M_A_CPU0_SA_DQ<31>")
	)
	(segment
		(start 316.140846 -280.150062)
		(end 316.03061 -280.039826)
		(width 0.20066)
		(layer "F.Cu")
		(net "M_A_CPU0_SA_DQ<31>")
	)
	(segment
		(start 316.03061 -280.039826)
		(end 316.03061 -279.818846)
		(width 0.20066)
		(layer "F.Cu")
		(net "M_A_CPU0_SA_DQ<31>")
	)
	(segment
		(start 316.606174 -280.150062)
		(end 316.140846 -280.150062)
		(width 0.20066)
		(layer "F.Cu")
		(net "M_A_CPU0_SA_DQ<31>")
	)
	(segment
		(start 332.05293 -264.599928)
		(end 331.879956 -264.772902)
		(width 0.088646)
		(layer "F.Cu")
		(net "M_A_CPU0_SA_DQ<31>")
	)
	(segment
		(start 333.122778 -265.185906)
		(end 332.827122 -264.89025)
		(width 0.088646)
		(layer "F.Cu")
		(net "M_A_CPU0_SA_DQ<31>")
	)
	(segment
		(start 334.046322 -265.277854)
		(end 334.046322 -265.023854)
		(width 0.088646)
		(layer "F.Cu")
		(net "M_A_CPU0_SA_DQ<31>")
	)
	(segment
		(start 321.40271 -278.66975)
		(end 321.28587 -278.55291)
		(width 0.1016)
		(layer "F.Cu")
		(net "M_A_CPU0_SA_DQ<31>")
	)
	(segment
		(start 331.868272 -264.901934)
		(end 331.778356 -264.99185)
		(width 0.1016)
		(layer "F.Cu")
		(net "M_A_CPU0_SA_DQ<31>")
	)
	(segment
		(start 332.391766 -264.599928)
		(end 332.05293 -264.599928)
		(width 0.088646)
		(layer "F.Cu")
		(net "M_A_CPU0_SA_DQ<31>")
	)
	(segment
		(start 332.827122 -264.89025)
		(end 332.682088 -264.89025)
		(width 0.088646)
		(layer "F.Cu")
		(net "M_A_CPU0_SA_DQ<31>")
	)
	(segment
		(start 307.25491 -279.892506)
		(end 307.25491 -280.105866)
		(width 0.20066)
		(layer "F.Cu")
		(net "M_A_CPU0_SA_DQ<31>")
	)
	(segment
		(start 315.455046 -279.70861)
		(end 315.34481 -279.818846)
		(width 0.20066)
		(layer "F.Cu")
		(net "M_A_CPU0_SA_DQ<31>")
	)
	(segment
		(start 316.826646 -279.70861)
		(end 316.71641 -279.818846)
		(width 0.20066)
		(layer "F.Cu")
		(net "M_A_CPU0_SA_DQ<31>")
	)
	(segment
		(start 331.016102 -264.99185)
		(end 330.86929 -265.138662)
		(width 0.1016)
		(layer "F.Cu")
		(net "M_A_CPU0_SA_DQ<31>")
	)
	(segment
		(start 324.017132 -273.389344)
		(end 322.46951 -276.284436)
		(width 0.1016)
		(layer "F.Cu")
		(net "M_A_CPU0_SA_DQ<31>")
	)
	(segment
		(start 321.28587 -278.196548)
		(end 321.149472 -278.06015)
		(width 0.1016)
		(layer "F.Cu")
		(net "M_A_CPU0_SA_DQ<31>")
	)
	(segment
		(start 322.46951 -276.284436)
		(end 322.06438 -278.319992)
		(width 0.1016)
		(layer "F.Cu")
		(net "M_A_CPU0_SA_DQ<31>")
	)
	(segment
		(start 334.431894 -265.18743)
		(end 334.431894 -265.358626)
		(width 0.088646)
		(layer "F.Cu")
		(net "M_A_CPU0_SA_DQ<31>")
	)
	(segment
		(start 314.027058 -279.929336)
		(end 313.864498 -279.766776)
		(width 0.20066)
		(layer "F.Cu")
		(net "M_A_CPU0_SA_DQ<31>")
	)
	(segment
		(start 317.40221 -279.818846)
		(end 317.291974 -279.70861)
		(width 0.20066)
		(layer "F.Cu")
		(net "M_A_CPU0_SA_DQ<31>")
	)
	(segment
		(start 318.663574 -279.70861)
		(end 318.198246 -279.70861)
		(width 0.20066)
		(layer "F.Cu")
		(net "M_A_CPU0_SA_DQ<31>")
	)
	(segment
		(start 318.77381 -279.818846)
		(end 318.663574 -279.70861)
		(width 0.20066)
		(layer "F.Cu")
		(net "M_A_CPU0_SA_DQ<31>")
	)
	(segment
		(start 317.40221 -280.039826)
		(end 317.40221 -279.818846)
		(width 0.20066)
		(layer "F.Cu")
		(net "M_A_CPU0_SA_DQ<31>")
	)
	(segment
		(start 307.76291 -280.207974)
		(end 307.779166 -280.191718)
		(width 0.101854)
		(layer "F.Cu")
		(net "M_A_CPU0_SA_DQ<31>")
	)
	(segment
		(start 316.71641 -279.818846)
		(end 316.71641 -280.039826)
		(width 0.20066)
		(layer "F.Cu")
		(net "M_A_CPU0_SA_DQ<31>")
	)
	(segment
		(start 318.198246 -279.70861)
		(end 318.08801 -279.818846)
		(width 0.20066)
		(layer "F.Cu")
		(net "M_A_CPU0_SA_DQ<31>")
	)
	(segment
		(start 330.790804 -266.615672)
		(end 324.017132 -273.389344)
		(width 0.1016)
		(layer "F.Cu")
		(net "M_A_CPU0_SA_DQ<31>")
	)
	(segment
		(start 308.047136 -280.191718)
		(end 309.828184 -280.191718)
		(width 0.1016)
		(layer "F.Cu")
		(net "M_A_CPU0_SA_DQ<31>")
	)
	(segment
		(start 333.53883 -265.185906)
		(end 333.122778 -265.185906)
		(width 0.088646)
		(layer "F.Cu")
		(net "M_A_CPU0_SA_DQ<31>")
	)
	(segment
		(start 311.736232 -279.47112)
		(end 312.031888 -279.766776)
		(width 0.20066)
		(layer "F.Cu")
		(net "M_A_CPU0_SA_DQ<31>")
	)
	(segment
		(start 331.219556 -265.696192)
		(end 331.219556 -266.089892)
		(width 0.1016)
		(layer "F.Cu")
		(net "M_A_CPU0_SA_DQ<31>")
	)
	(segment
		(start 319.330578 -279.929336)
		(end 318.884046 -279.929336)
		(width 0.20066)
		(layer "F.Cu")
		(net "M_A_CPU0_SA_DQ<31>")
	)
	(segment
		(start 334.864456 -265.07948)
		(end 334.772508 -264.987532)
		(width 0.088646)
		(layer "F.Cu")
		(net "M_A_CPU0_SA_DQ<31>")
	)
	(segment
		(start 321.638676 -278.66975)
		(end 321.40271 -278.66975)
		(width 0.1016)
		(layer "F.Cu")
		(net "M_A_CPU0_SA_DQ<31>")
	)
	(segment
		(start 320.699892 -278.277066)
		(end 320.699892 -278.560022)
		(width 0.1016)
		(layer "F.Cu")
		(net "M_A_CPU0_SA_DQ<31>")
	)
	(segment
		(start 315.34481 -279.818846)
		(end 315.34481 -280.039826)
		(width 0.20066)
		(layer "F.Cu")
		(net "M_A_CPU0_SA_DQ<31>")
	)
	(segment
		(start 322.06438 -278.319992)
		(end 321.638676 -278.66975)
		(width 0.1016)
		(layer "F.Cu")
		(net "M_A_CPU0_SA_DQ<31>")
	)
	(segment
		(start 318.77381 -279.8191)
		(end 318.77381 -279.818846)
		(width 0.20066)
		(layer "F.Cu")
		(net "M_A_CPU0_SA_DQ<31>")
	)
	(segment
		(start 320.916808 -278.06015)
		(end 320.699892 -278.277066)
		(width 0.1016)
		(layer "F.Cu")
		(net "M_A_CPU0_SA_DQ<31>")
	)
	(segment
		(start 307.357018 -280.207974)
		(end 307.76291 -280.207974)
		(width 0.20066)
		(layer "F.Cu")
		(net "M_A_CPU0_SA_DQ<31>")
	)
	(segment
		(start 310.235346 -280.197306)
		(end 310.961532 -279.47112)
		(width 0.20066)
		(layer "F.Cu")
		(net "M_A_CPU0_SA_DQ<31>")
	)
	(segment
		(start 330.977748 -266.191492)
		(end 330.790804 -266.378436)
		(width 0.1016)
		(layer "F.Cu")
		(net "M_A_CPU0_SA_DQ<31>")
	)
	(segment
		(start 321.149472 -278.06015)
		(end 320.916808 -278.06015)
		(width 0.1016)
		(layer "F.Cu")
		(net "M_A_CPU0_SA_DQ<31>")
	)
	(segment
		(start 330.977748 -265.594592)
		(end 331.117956 -265.594592)
		(width 0.1016)
		(layer "F.Cu")
		(net "M_A_CPU0_SA_DQ<31>")
	)
	(segment
		(start 334.203294 -265.434826)
		(end 334.046322 -265.277854)
		(width 0.088646)
		(layer "F.Cu")
		(net "M_A_CPU0_SA_DQ<31>")
	)
	(segment
		(start 312.031888 -279.766776)
		(end 312.987182 -279.766776)
		(width 0.20066)
		(layer "F.Cu")
		(net "M_A_CPU0_SA_DQ<31>")
	)
	(segment
		(start 334.785716 -265.347958)
		(end 334.864456 -265.269218)
		(width 0.088646)
		(layer "F.Cu")
		(net "M_A_CPU0_SA_DQ<31>")
	)
	(segment
		(start 330.790804 -266.378436)
		(end 330.790804 -266.615672)
		(width 0.1016)
		(layer "F.Cu")
		(net "M_A_CPU0_SA_DQ<31>")
	)
	(segment
		(start 317.512446 -280.150062)
		(end 317.40221 -280.039826)
		(width 0.20066)
		(layer "F.Cu")
		(net "M_A_CPU0_SA_DQ<31>")
	)
	(segment
		(start 307.779166 -280.191718)
		(end 308.047136 -280.191718)
		(width 0.101854)
		(layer "F.Cu")
		(net "M_A_CPU0_SA_DQ<31>")
	)
	(segment
		(start 314.367926 -279.929336)
		(end 314.027058 -279.929336)
		(width 0.20066)
		(layer "F.Cu")
		(net "M_A_CPU0_SA_DQ<31>")
	)
	(segment
		(start 320.413126 -278.846788)
		(end 319.330578 -279.929336)
		(width 0.20066)
		(layer "F.Cu")
		(net "M_A_CPU0_SA_DQ<31>")
	)
	(segment
		(start 318.08801 -280.039826)
		(end 317.977774 -280.150062)
		(width 0.20066)
		(layer "F.Cu")
		(net "M_A_CPU0_SA_DQ<31>")
	)
	(segment
		(start 310.088026 -280.197306)
		(end 310.235346 -280.197306)
		(width 0.20066)
		(layer "F.Cu")
		(net "M_A_CPU0_SA_DQ<31>")
	)
	(segment
		(start 330.86929 -265.486134)
		(end 330.977748 -265.594592)
		(width 0.1016)
		(layer "F.Cu")
		(net "M_A_CPU0_SA_DQ<31>")
	)
	(segment
		(start 315.920374 -279.70861)
		(end 315.455046 -279.70861)
		(width 0.20066)
		(layer "F.Cu")
		(net "M_A_CPU0_SA_DQ<31>")
	)
	(segment
		(start 331.219556 -266.089892)
		(end 331.117956 -266.191492)
		(width 0.1016)
		(layer "F.Cu")
		(net "M_A_CPU0_SA_DQ<31>")
	)
	(segment
		(start 331.879956 -264.89025)
		(end 331.868272 -264.901934)
		(width 0.088646)
		(layer "F.Cu")
		(net "M_A_CPU0_SA_DQ<31>")
	)
	(segment
		(start 318.884046 -279.929336)
		(end 318.77381 -279.8191)
		(width 0.20066)
		(layer "F.Cu")
		(net "M_A_CPU0_SA_DQ<31>")
	)
	(segment
		(start 333.76489 -264.901426)
		(end 333.616808 -265.049508)
		(width 0.088646)
		(layer "F.Cu")
		(net "M_A_CPU0_SA_DQ<31>")
	)
	(segment
		(start 318.08801 -279.818846)
		(end 318.08801 -280.039826)
		(width 0.20066)
		(layer "F.Cu")
		(net "M_A_CPU0_SA_DQ<31>")
	)
	(segment
		(start 315.234574 -280.150062)
		(end 314.588652 -280.150062)
		(width 0.20066)
		(layer "F.Cu")
		(net "M_A_CPU0_SA_DQ<31>")
	)
	(segment
		(start 331.117956 -266.191492)
		(end 330.977748 -266.191492)
		(width 0.1016)
		(layer "F.Cu")
		(net "M_A_CPU0_SA_DQ<31>")
	)
	(segment
		(start 316.03061 -279.818846)
		(end 315.920374 -279.70861)
		(width 0.20066)
		(layer "F.Cu")
		(net "M_A_CPU0_SA_DQ<31>")
	)
	(segment
		(start 310.891682 -281.595068)
		(end 311.019952 -281.466798)
		(width 0.20066)
		(layer "F.Cu")
		(net "M_A_CPU0_SA_DQ<30>")
	)
	(segment
		(start 307.962046 -281.026362)
		(end 307.977286 -281.041602)
		(width 0.101854)
		(layer "F.Cu")
		(net "M_A_CPU0_SA_DQ<30>")
	)
	(segment
		(start 316.142116 -281.870912)
		(end 315.941456 -282.071572)
		(width 0.20066)
		(layer "F.Cu")
		(net "M_A_CPU0_SA_DQ<30>")
	)
	(segment
		(start 307.15204 -281.026362)
		(end 307.76291 -281.026362)
		(width 0.20066)
		(layer "F.Cu")
		(net "M_A_CPU0_SA_DQ<30>")
	)
	(segment
		(start 335.183988 -265.707876)
		(end 334.939894 -265.95197)
		(width 0.088646)
		(layer "F.Cu")
		(net "M_A_CPU0_SA_DQ<30>")
	)
	(segment
		(start 316.342776 -281.45994)
		(end 316.142116 -281.6606)
		(width 0.20066)
		(layer "F.Cu")
		(net "M_A_CPU0_SA_DQ<30>")
	)
	(segment
		(start 317.053976 -282.066238)
		(end 316.853316 -281.865578)
		(width 0.20066)
		(layer "F.Cu")
		(net "M_A_CPU0_SA_DQ<30>")
	)
	(segment
		(start 334.609694 -265.951208)
		(end 334.365346 -265.70686)
		(width 0.088646)
		(layer "F.Cu")
		(net "M_A_CPU0_SA_DQ<30>")
	)
	(segment
		(start 316.142116 -281.6606)
		(end 316.142116 -281.870912)
		(width 0.20066)
		(layer "F.Cu")
		(net "M_A_CPU0_SA_DQ<30>")
	)
	(segment
		(start 307.76291 -281.026362)
		(end 307.962046 -281.026362)
		(width 0.101854)
		(layer "F.Cu")
		(net "M_A_CPU0_SA_DQ<30>")
	)
	(segment
		(start 315.225176 -281.45486)
		(end 314.449968 -281.45486)
		(width 0.20066)
		(layer "F.Cu")
		(net "M_A_CPU0_SA_DQ<30>")
	)
	(segment
		(start 318.075056 -281.45994)
		(end 317.765176 -281.45994)
		(width 0.20066)
		(layer "F.Cu")
		(net "M_A_CPU0_SA_DQ<30>")
	)
	(segment
		(start 335.255362 -266.080748)
		(end 335.397602 -265.938508)
		(width 0.088646)
		(layer "F.Cu")
		(net "M_A_CPU0_SA_DQ<30>")
	)
	(segment
		(start 318.786256 -282.060904)
		(end 318.476376 -282.060904)
		(width 0.20066)
		(layer "F.Cu")
		(net "M_A_CPU0_SA_DQ<30>")
	)
	(segment
		(start 307.977286 -281.041602)
		(end 309.804054 -281.041602)
		(width 0.1016)
		(layer "F.Cu")
		(net "M_A_CPU0_SA_DQ<30>")
	)
	(segment
		(start 310.088026 -281.040586)
		(end 310.315102 -281.040586)
		(width 0.20066)
		(layer "F.Cu")
		(net "M_A_CPU0_SA_DQ<30>")
	)
	(segment
		(start 333.683864 -265.989562)
		(end 333.63662 -265.942318)
		(width 0.088646)
		(layer "F.Cu")
		(net "M_A_CPU0_SA_DQ<30>")
	)
	(segment
		(start 315.430916 -281.6606)
		(end 315.225176 -281.45486)
		(width 0.20066)
		(layer "F.Cu")
		(net "M_A_CPU0_SA_DQ<30>")
	)
	(segment
		(start 334.939894 -266.177014)
		(end 334.836262 -266.280646)
		(width 0.088646)
		(layer "F.Cu")
		(net "M_A_CPU0_SA_DQ<30>")
	)
	(segment
		(start 318.275716 -281.860244)
		(end 318.275716 -281.6606)
		(width 0.20066)
		(layer "F.Cu")
		(net "M_A_CPU0_SA_DQ<30>")
	)
	(segment
		(start 334.098138 -266.09802)
		(end 333.887572 -266.308586)
		(width 0.088646)
		(layer "F.Cu")
		(net "M_A_CPU0_SA_DQ<30>")
	)
	(segment
		(start 316.853316 -281.865578)
		(end 316.853316 -281.6606)
		(width 0.20066)
		(layer "F.Cu")
		(net "M_A_CPU0_SA_DQ<30>")
	)
	(segment
		(start 332.380844 -266.182348)
		(end 332.195932 -265.997436)
		(width 0.088646)
		(layer "F.Cu")
		(net "M_A_CPU0_SA_DQ<30>")
	)
	(segment
		(start 307.04282 -281.135582)
		(end 307.15204 -281.026362)
		(width 0.20066)
		(layer "F.Cu")
		(net "M_A_CPU0_SA_DQ<30>")
	)
	(segment
		(start 311.019952 -281.466798)
		(end 312.987182 -281.466798)
		(width 0.20066)
		(layer "F.Cu")
		(net "M_A_CPU0_SA_DQ<30>")
	)
	(segment
		(start 310.315102 -281.040586)
		(end 310.457088 -281.182572)
		(width 0.20066)
		(layer "F.Cu")
		(net "M_A_CPU0_SA_DQ<30>")
	)
	(segment
		(start 315.631576 -282.071572)
		(end 315.430916 -281.870912)
		(width 0.20066)
		(layer "F.Cu")
		(net "M_A_CPU0_SA_DQ<30>")
	)
	(segment
		(start 332.97241 -266.182348)
		(end 332.380844 -266.182348)
		(width 0.088646)
		(layer "F.Cu")
		(net "M_A_CPU0_SA_DQ<30>")
	)
	(segment
		(start 317.564516 -281.6606)
		(end 317.564516 -281.865578)
		(width 0.20066)
		(layer "F.Cu")
		(net "M_A_CPU0_SA_DQ<30>")
	)
	(segment
		(start 318.275716 -281.6606)
		(end 318.075056 -281.45994)
		(width 0.20066)
		(layer "F.Cu")
		(net "M_A_CPU0_SA_DQ<30>")
	)
	(segment
		(start 331.9145 -265.997436)
		(end 331.841856 -266.07008)
		(width 0.1016)
		(layer "F.Cu")
		(net "M_A_CPU0_SA_DQ<30>")
	)
	(segment
		(start 310.457088 -281.422094)
		(end 310.630062 -281.595068)
		(width 0.20066)
		(layer "F.Cu")
		(net "M_A_CPU0_SA_DQ<30>")
	)
	(segment
		(start 322.575682 -278.879808)
		(end 321.995546 -279.459944)
		(width 0.1016)
		(layer "F.Cu")
		(net "M_A_CPU0_SA_DQ<30>")
	)
	(segment
		(start 321.320414 -279.754076)
		(end 319.61455 -281.45994)
		(width 0.20066)
		(layer "F.Cu")
		(net "M_A_CPU0_SA_DQ<30>")
	)
	(segment
		(start 334.70469 -266.280646)
		(end 334.609694 -266.18565)
		(width 0.088646)
		(layer "F.Cu")
		(net "M_A_CPU0_SA_DQ<30>")
	)
	(segment
		(start 319.187576 -281.45994)
		(end 318.986916 -281.6606)
		(width 0.20066)
		(layer "F.Cu")
		(net "M_A_CPU0_SA_DQ<30>")
	)
	(segment
		(start 307.04282 -281.324558)
		(end 307.04282 -281.135582)
		(width 0.20066)
		(layer "F.Cu")
		(net "M_A_CPU0_SA_DQ<30>")
	)
	(segment
		(start 331.841856 -266.42822)
		(end 324.512178 -273.757898)
		(width 0.1016)
		(layer "F.Cu")
		(net "M_A_CPU0_SA_DQ<30>")
	)
	(segment
		(start 333.887572 -266.308586)
		(end 333.79156 -266.308586)
		(width 0.088646)
		(layer "F.Cu")
		(net "M_A_CPU0_SA_DQ<30>")
	)
	(segment
		(start 333.79156 -266.308586)
		(end 333.683864 -266.20089)
		(width 0.088646)
		(layer "F.Cu")
		(net "M_A_CPU0_SA_DQ<30>")
	)
	(segment
		(start 335.397602 -265.938508)
		(end 335.397602 -265.770614)
		(width 0.088646)
		(layer "F.Cu")
		(net "M_A_CPU0_SA_DQ<30>")
	)
	(segment
		(start 321.614546 -279.459944)
		(end 321.320414 -279.754076)
		(width 0.1016)
		(layer "F.Cu")
		(net "M_A_CPU0_SA_DQ<30>")
	)
	(segment
		(start 321.995546 -279.459944)
		(end 321.614546 -279.459944)
		(width 0.1016)
		(layer "F.Cu")
		(net "M_A_CPU0_SA_DQ<30>")
	)
	(segment
		(start 309.80507 -281.040586)
		(end 310.088026 -281.040586)
		(width 0.101854)
		(layer "F.Cu")
		(net "M_A_CPU0_SA_DQ<30>")
	)
	(segment
		(start 334.836262 -266.280646)
		(end 334.70469 -266.280646)
		(width 0.088646)
		(layer "F.Cu")
		(net "M_A_CPU0_SA_DQ<30>")
	)
	(segment
		(start 335.255362 -266.405868)
		(end 335.255362 -266.080748)
		(width 0.088646)
		(layer "F.Cu")
		(net "M_A_CPU0_SA_DQ<30>")
	)
	(segment
		(start 334.098138 -265.861546)
		(end 334.098138 -266.09802)
		(width 0.088646)
		(layer "F.Cu")
		(net "M_A_CPU0_SA_DQ<30>")
	)
	(segment
		(start 306.90058 -281.466798)
		(end 307.04282 -281.324558)
		(width 0.20066)
		(layer "F.Cu")
		(net "M_A_CPU0_SA_DQ<30>")
	)
	(segment
		(start 314.43803 -281.466798)
		(end 312.987182 -281.466798)
		(width 0.20066)
		(layer "F.Cu")
		(net "M_A_CPU0_SA_DQ<30>")
	)
	(segment
		(start 318.986916 -281.860244)
		(end 318.786256 -282.060904)
		(width 0.20066)
		(layer "F.Cu")
		(net "M_A_CPU0_SA_DQ<30>")
	)
	(segment
		(start 318.986916 -281.6606)
		(end 318.986916 -281.860244)
		(width 0.20066)
		(layer "F.Cu")
		(net "M_A_CPU0_SA_DQ<30>")
	)
	(segment
		(start 323.050154 -276.49297)
		(end 322.575682 -278.879808)
		(width 0.1016)
		(layer "F.Cu")
		(net "M_A_CPU0_SA_DQ<30>")
	)
	(segment
		(start 318.476376 -282.060904)
		(end 318.275716 -281.860244)
		(width 0.20066)
		(layer "F.Cu")
		(net "M_A_CPU0_SA_DQ<30>")
	)
	(segment
		(start 334.365346 -265.70686)
		(end 334.252824 -265.70686)
		(width 0.088646)
		(layer "F.Cu")
		(net "M_A_CPU0_SA_DQ<30>")
	)
	(segment
		(start 332.0669 -265.997436)
		(end 331.9145 -265.997436)
		(width 0.1016)
		(layer "F.Cu")
		(net "M_A_CPU0_SA_DQ<30>")
	)
	(segment
		(start 324.512178 -273.757898)
		(end 323.050154 -276.49297)
		(width 0.1016)
		(layer "F.Cu")
		(net "M_A_CPU0_SA_DQ<30>")
	)
	(segment
		(start 317.765176 -281.45994)
		(end 317.564516 -281.6606)
		(width 0.20066)
		(layer "F.Cu")
		(net "M_A_CPU0_SA_DQ<30>")
	)
	(segment
		(start 333.520796 -265.942318)
		(end 332.97241 -266.182348)
		(width 0.088646)
		(layer "F.Cu")
		(net "M_A_CPU0_SA_DQ<30>")
	)
	(segment
		(start 333.683864 -266.20089)
		(end 333.683864 -265.989562)
		(width 0.088646)
		(layer "F.Cu")
		(net "M_A_CPU0_SA_DQ<30>")
	)
	(segment
		(start 334.252824 -265.70686)
		(end 334.098138 -265.861546)
		(width 0.088646)
		(layer "F.Cu")
		(net "M_A_CPU0_SA_DQ<30>")
	)
	(segment
		(start 316.652656 -281.45994)
		(end 316.342776 -281.45994)
		(width 0.20066)
		(layer "F.Cu")
		(net "M_A_CPU0_SA_DQ<30>")
	)
	(segment
		(start 310.630062 -281.595068)
		(end 310.891682 -281.595068)
		(width 0.20066)
		(layer "F.Cu")
		(net "M_A_CPU0_SA_DQ<30>")
	)
	(segment
		(start 331.841856 -266.07008)
		(end 331.841856 -266.42822)
		(width 0.1016)
		(layer "F.Cu")
		(net "M_A_CPU0_SA_DQ<30>")
	)
	(segment
		(start 309.804054 -281.041602)
		(end 309.80507 -281.040586)
		(width 0.1016)
		(layer "F.Cu")
		(net "M_A_CPU0_SA_DQ<30>")
	)
	(segment
		(start 310.457088 -281.182572)
		(end 310.457088 -281.422094)
		(width 0.20066)
		(layer "F.Cu")
		(net "M_A_CPU0_SA_DQ<30>")
	)
	(segment
		(start 335.397602 -265.770614)
		(end 335.334864 -265.707876)
		(width 0.088646)
		(layer "F.Cu")
		(net "M_A_CPU0_SA_DQ<30>")
	)
	(segment
		(start 316.853316 -281.6606)
		(end 316.652656 -281.45994)
		(width 0.20066)
		(layer "F.Cu")
		(net "M_A_CPU0_SA_DQ<30>")
	)
	(segment
		(start 315.941456 -282.071572)
		(end 315.631576 -282.071572)
		(width 0.20066)
		(layer "F.Cu")
		(net "M_A_CPU0_SA_DQ<30>")
	)
	(segment
		(start 333.63662 -265.942318)
		(end 333.520796 -265.942318)
		(width 0.088646)
		(layer "F.Cu")
		(net "M_A_CPU0_SA_DQ<30>")
	)
	(segment
		(start 317.363856 -282.066238)
		(end 317.053976 -282.066238)
		(width 0.20066)
		(layer "F.Cu")
		(net "M_A_CPU0_SA_DQ<30>")
	)
	(segment
		(start 315.430916 -281.870912)
		(end 315.430916 -281.6606)
		(width 0.20066)
		(layer "F.Cu")
		(net "M_A_CPU0_SA_DQ<30>")
	)
	(segment
		(start 334.939894 -265.95197)
		(end 334.939894 -266.177014)
		(width 0.088646)
		(layer "F.Cu")
		(net "M_A_CPU0_SA_DQ<30>")
	)
	(segment
		(start 334.609694 -266.18565)
		(end 334.609694 -265.951208)
		(width 0.088646)
		(layer "F.Cu")
		(net "M_A_CPU0_SA_DQ<30>")
	)
	(segment
		(start 314.449968 -281.45486)
		(end 314.43803 -281.466798)
		(width 0.20066)
		(layer "F.Cu")
		(net "M_A_CPU0_SA_DQ<30>")
	)
	(segment
		(start 335.334864 -265.707876)
		(end 335.183988 -265.707876)
		(width 0.088646)
		(layer "F.Cu")
		(net "M_A_CPU0_SA_DQ<30>")
	)
	(segment
		(start 332.195932 -265.997436)
		(end 332.0669 -265.997436)
		(width 0.088646)
		(layer "F.Cu")
		(net "M_A_CPU0_SA_DQ<30>")
	)
	(segment
		(start 317.564516 -281.865578)
		(end 317.363856 -282.066238)
		(width 0.20066)
		(layer "F.Cu")
		(net "M_A_CPU0_SA_DQ<30>")
	)
	(segment
		(start 319.61455 -281.45994)
		(end 319.187576 -281.45994)
		(width 0.20066)
		(layer "F.Cu")
		(net "M_A_CPU0_SA_DQ<30>")
	)
	(segment
		(start 305.443382 -281.466798)
		(end 306.90058 -281.466798)
		(width 0.20066)
		(layer "F.Cu")
		(net "M_A_CPU0_SA_DQ<30>")
	)
	(segment
		(start 314.398152 -315.46673)
		(end 312.987182 -315.46673)
		(width 0.20066)
		(layer "F.Cu")
		(net "M_A_CPU0_SA_DQ<2>")
	)
	(segment
		(start 310.304942 -315.042296)
		(end 310.457088 -315.194442)
		(width 0.20066)
		(layer "F.Cu")
		(net "M_A_CPU0_SA_DQ<2>")
	)
	(segment
		(start 332.47838 -297.266868)
		(end 332.333092 -298.244514)
		(width 0.1016)
		(layer "F.Cu")
		(net "M_A_CPU0_SA_DQ<2>")
	)
	(segment
		(start 333.828644 -279.455626)
		(end 333.808324 -279.482042)
		(width 0.088646)
		(layer "F.Cu")
		(net "M_A_CPU0_SA_DQ<2>")
	)
	(segment
		(start 314.917582 -315.251592)
		(end 314.398152 -315.46673)
		(width 0.20066)
		(layer "F.Cu")
		(net "M_A_CPU0_SA_DQ<2>")
	)
	(segment
		(start 334.128364 -279.103836)
		(end 334.049624 -279.149302)
		(width 0.088646)
		(layer "F.Cu")
		(net "M_A_CPU0_SA_DQ<2>")
	)
	(segment
		(start 332.806548 -281.08529)
		(end 332.718664 -281.329892)
		(width 0.1016)
		(layer "F.Cu")
		(net "M_A_CPU0_SA_DQ<2>")
	)
	(segment
		(start 310.012842 -315.042296)
		(end 310.07177 -315.042296)
		(width 0.101854)
		(layer "F.Cu")
		(net "M_A_CPU0_SA_DQ<2>")
	)
	(segment
		(start 335.81848 -278.978868)
		(end 335.528158 -278.978868)
		(width 0.088646)
		(layer "F.Cu")
		(net "M_A_CPU0_SA_DQ<2>")
	)
	(segment
		(start 306.755546 -315.46673)
		(end 307.193442 -315.028834)
		(width 0.20066)
		(layer "F.Cu")
		(net "M_A_CPU0_SA_DQ<2>")
	)
	(segment
		(start 337.425538 -278.105108)
		(end 337.15833 -278.16937)
		(width 0.088646)
		(layer "F.Cu")
		(net "M_A_CPU0_SA_DQ<2>")
	)
	(segment
		(start 316.870588 -314.442348)
		(end 314.917582 -315.251592)
		(width 0.20066)
		(layer "F.Cu")
		(net "M_A_CPU0_SA_DQ<2>")
	)
	(segment
		(start 310.457088 -315.194442)
		(end 310.457088 -315.499242)
		(width 0.20066)
		(layer "F.Cu")
		(net "M_A_CPU0_SA_DQ<2>")
	)
	(segment
		(start 332.333092 -298.244514)
		(end 332.061058 -299.610018)
		(width 0.1016)
		(layer "F.Cu")
		(net "M_A_CPU0_SA_DQ<2>")
	)
	(segment
		(start 307.746654 -315.028834)
		(end 307.749194 -315.028834)
		(width 0.101854)
		(layer "F.Cu")
		(net "M_A_CPU0_SA_DQ<2>")
	)
	(segment
		(start 311.26938 -315.46673)
		(end 312.987182 -315.46673)
		(width 0.20066)
		(layer "F.Cu")
		(net "M_A_CPU0_SA_DQ<2>")
	)
	(segment
		(start 332.061058 -299.610018)
		(end 332.061058 -299.685456)
		(width 0.1016)
		(layer "F.Cu")
		(net "M_A_CPU0_SA_DQ<2>")
	)
	(segment
		(start 332.47838 -282.529026)
		(end 332.47838 -297.266868)
		(width 0.1016)
		(layer "F.Cu")
		(net "M_A_CPU0_SA_DQ<2>")
	)
	(segment
		(start 333.808324 -279.482042)
		(end 333.809848 -279.49271)
		(width 0.088646)
		(layer "F.Cu")
		(net "M_A_CPU0_SA_DQ<2>")
	)
	(segment
		(start 310.638444 -315.680598)
		(end 311.055512 -315.680598)
		(width 0.20066)
		(layer "F.Cu")
		(net "M_A_CPU0_SA_DQ<2>")
	)
	(segment
		(start 307.761894 -315.041534)
		(end 307.80228 -315.041534)
		(width 0.101854)
		(layer "F.Cu")
		(net "M_A_CPU0_SA_DQ<2>")
	)
	(segment
		(start 333.809848 -279.49271)
		(end 333.47025 -279.948132)
		(width 0.088646)
		(layer "F.Cu")
		(net "M_A_CPU0_SA_DQ<2>")
	)
	(segment
		(start 337.15833 -278.16937)
		(end 336.563716 -278.24303)
		(width 0.088646)
		(layer "F.Cu")
		(net "M_A_CPU0_SA_DQ<2>")
	)
	(segment
		(start 336.3341 -278.406098)
		(end 336.003646 -278.851614)
		(width 0.088646)
		(layer "F.Cu")
		(net "M_A_CPU0_SA_DQ<2>")
	)
	(segment
		(start 307.80228 -315.041534)
		(end 310.01208 -315.041534)
		(width 0.1016)
		(layer "F.Cu")
		(net "M_A_CPU0_SA_DQ<2>")
	)
	(segment
		(start 307.749194 -315.028834)
		(end 307.761894 -315.041534)
		(width 0.101854)
		(layer "F.Cu")
		(net "M_A_CPU0_SA_DQ<2>")
	)
	(segment
		(start 333.911956 -279.331928)
		(end 333.828644 -279.455626)
		(width 0.088646)
		(layer "F.Cu")
		(net "M_A_CPU0_SA_DQ<2>")
	)
	(segment
		(start 336.563716 -278.24303)
		(end 336.41665 -278.314912)
		(width 0.088646)
		(layer "F.Cu")
		(net "M_A_CPU0_SA_DQ<2>")
	)
	(segment
		(start 307.193442 -315.028834)
		(end 307.746654 -315.028834)
		(width 0.20066)
		(layer "F.Cu")
		(net "M_A_CPU0_SA_DQ<2>")
	)
	(segment
		(start 310.01208 -315.041534)
		(end 310.012842 -315.042296)
		(width 0.101854)
		(layer "F.Cu")
		(net "M_A_CPU0_SA_DQ<2>")
	)
	(segment
		(start 335.91754 -278.93772)
		(end 335.81848 -278.978868)
		(width 0.088646)
		(layer "F.Cu")
		(net "M_A_CPU0_SA_DQ<2>")
	)
	(segment
		(start 335.068164 -279.103836)
		(end 335.053432 -279.112472)
		(width 0.088646)
		(layer "F.Cu")
		(net "M_A_CPU0_SA_DQ<2>")
	)
	(segment
		(start 332.718664 -281.329892)
		(end 332.47838 -282.529026)
		(width 0.1016)
		(layer "F.Cu")
		(net "M_A_CPU0_SA_DQ<2>")
	)
	(segment
		(start 338.074762 -277.800562)
		(end 337.425538 -278.105108)
		(width 0.088646)
		(layer "F.Cu")
		(net "M_A_CPU0_SA_DQ<2>")
	)
	(segment
		(start 310.457088 -315.499242)
		(end 310.638444 -315.680598)
		(width 0.20066)
		(layer "F.Cu")
		(net "M_A_CPU0_SA_DQ<2>")
	)
	(segment
		(start 310.07177 -315.042296)
		(end 310.304942 -315.042296)
		(width 0.20066)
		(layer "F.Cu")
		(net "M_A_CPU0_SA_DQ<2>")
	)
	(segment
		(start 331.982318 -299.764196)
		(end 318.177418 -313.569096)
		(width 0.20066)
		(layer "F.Cu")
		(net "M_A_CPU0_SA_DQ<2>")
	)
	(segment
		(start 333.272892 -280.21407)
		(end 332.806548 -281.08529)
		(width 0.1016)
		(layer "F.Cu")
		(net "M_A_CPU0_SA_DQ<2>")
	)
	(segment
		(start 336.41665 -278.314912)
		(end 336.3341 -278.406098)
		(width 0.088646)
		(layer "F.Cu")
		(net "M_A_CPU0_SA_DQ<2>")
	)
	(segment
		(start 318.177418 -313.569096)
		(end 316.870588 -314.442348)
		(width 0.20066)
		(layer "F.Cu")
		(net "M_A_CPU0_SA_DQ<2>")
	)
	(segment
		(start 332.061058 -299.685456)
		(end 331.982318 -299.764196)
		(width 0.1016)
		(layer "F.Cu")
		(net "M_A_CPU0_SA_DQ<2>")
	)
	(segment
		(start 311.055512 -315.680598)
		(end 311.26938 -315.46673)
		(width 0.20066)
		(layer "F.Cu")
		(net "M_A_CPU0_SA_DQ<2>")
	)
	(segment
		(start 305.443382 -315.46673)
		(end 306.755546 -315.46673)
		(width 0.20066)
		(layer "F.Cu")
		(net "M_A_CPU0_SA_DQ<2>")
	)
	(segment
		(start 336.003646 -278.851614)
		(end 335.91754 -278.93772)
		(width 0.088646)
		(layer "F.Cu")
		(net "M_A_CPU0_SA_DQ<2>")
	)
	(segment
		(start 333.47025 -279.948132)
		(end 333.272892 -280.21407)
		(width 0.1016)
		(layer "F.Cu")
		(net "M_A_CPU0_SA_DQ<2>")
	)
	(arc
		(start 335.528158 -278.978868)
		(mid 335.289829 -279.010674)
		(end 335.068164 -279.103836)
		(width 0.088646)
		(layer "F.Cu")
		(net "M_A_CPU0_SA_DQ<2>")
	)
	(arc
		(start 335.053432 -279.112472)
		(mid 334.776957 -279.179792)
		(end 334.50276 -279.103836)
		(width 0.088646)
		(layer "F.Cu")
		(net "M_A_CPU0_SA_DQ<2>")
	)
	(arc
		(start 334.049624 -279.149302)
		(mid 333.993639 -279.193961)
		(end 333.953358 -279.253188)
		(width 0.088646)
		(layer "F.Cu")
		(net "M_A_CPU0_SA_DQ<2>")
	)
	(arc
		(start 333.953358 -279.253188)
		(mid 333.933458 -279.292979)
		(end 333.911956 -279.331928)
		(width 0.088646)
		(layer "F.Cu")
		(net "M_A_CPU0_SA_DQ<2>")
	)
	(arc
		(start 334.50276 -279.103836)
		(mid 334.315562 -279.053693)
		(end 334.128364 -279.103836)
		(width 0.088646)
		(layer "F.Cu")
		(net "M_A_CPU0_SA_DQ<2>")
	)
	(segment
		(start 302.805846 -280.831544)
		(end 302.973232 -280.664158)
		(width 0.20066)
		(layer "F.Cu")
		(net "M_A_CPU0_SA_DQ<29>")
	)
	(segment
		(start 313.843416 -281.041602)
		(end 312.12536 -281.041602)
		(width 0.1016)
		(layer "F.Cu")
		(net "M_A_CPU0_SA_DQ<29>")
	)
	(segment
		(start 321.046094 -279.122124)
		(end 320.867278 -279.30094)
		(width 0.1016)
		(layer "F.Cu")
		(net "M_A_CPU0_SA_DQ<29>")
	)
	(segment
		(start 331.530198 -265.671554)
		(end 331.530198 -266.307824)
		(width 0.1016)
		(layer "F.Cu")
		(net "M_A_CPU0_SA_DQ<29>")
	)
	(segment
		(start 332.553056 -265.969496)
		(end 332.17739 -265.59383)
		(width 0.088646)
		(layer "F.Cu")
		(net "M_A_CPU0_SA_DQ<29>")
	)
	(segment
		(start 311.02427 -280.06294)
		(end 310.47055 -280.61666)
		(width 0.20066)
		(layer "F.Cu")
		(net "M_A_CPU0_SA_DQ<29>")
	)
	(segment
		(start 304.338228 -280.191718)
		(end 306.60848 -280.191718)
		(width 0.1016)
		(layer "F.Cu")
		(net "M_A_CPU0_SA_DQ<29>")
	)
	(segment
		(start 303.135538 -280.172668)
		(end 304.319178 -280.172668)
		(width 0.20066)
		(layer "F.Cu")
		(net "M_A_CPU0_SA_DQ<29>")
	)
	(segment
		(start 306.751228 -280.191718)
		(end 307.17617 -280.61666)
		(width 0.20066)
		(layer "F.Cu")
		(net "M_A_CPU0_SA_DQ<29>")
	)
	(segment
		(start 311.279286 -280.06294)
		(end 311.02427 -280.06294)
		(width 0.20066)
		(layer "F.Cu")
		(net "M_A_CPU0_SA_DQ<29>")
	)
	(segment
		(start 314.555378 -280.815288)
		(end 314.317634 -281.053032)
		(width 0.20066)
		(layer "F.Cu")
		(net "M_A_CPU0_SA_DQ<29>")
	)
	(segment
		(start 312.066178 -281.062176)
		(end 311.91708 -281.062176)
		(width 0.101854)
		(layer "F.Cu")
		(net "M_A_CPU0_SA_DQ<29>")
	)
	(segment
		(start 320.867278 -279.30094)
		(end 319.35293 -280.815288)
		(width 0.20066)
		(layer "F.Cu")
		(net "M_A_CPU0_SA_DQ<29>")
	)
	(segment
		(start 311.395618 -280.179272)
		(end 311.279286 -280.06294)
		(width 0.20066)
		(layer "F.Cu")
		(net "M_A_CPU0_SA_DQ<29>")
	)
	(segment
		(start 302.973232 -280.334974)
		(end 303.135538 -280.172668)
		(width 0.20066)
		(layer "F.Cu")
		(net "M_A_CPU0_SA_DQ<29>")
	)
	(segment
		(start 333.243174 -265.4808)
		(end 333.243174 -265.83005)
		(width 0.088646)
		(layer "F.Cu")
		(net "M_A_CPU0_SA_DQ<29>")
	)
	(segment
		(start 332.899766 -265.969496)
		(end 332.553056 -265.969496)
		(width 0.088646)
		(layer "F.Cu")
		(net "M_A_CPU0_SA_DQ<29>")
	)
	(segment
		(start 306.60848 -280.191718)
		(end 306.644294 -280.191718)
		(width 0.101854)
		(layer "F.Cu")
		(net "M_A_CPU0_SA_DQ<29>")
	)
	(segment
		(start 310.47055 -280.61666)
		(end 308.887114 -280.61666)
		(width 0.20066)
		(layer "F.Cu")
		(net "M_A_CPU0_SA_DQ<29>")
	)
	(segment
		(start 314.317634 -281.053032)
		(end 314.15228 -281.053032)
		(width 0.20066)
		(layer "F.Cu")
		(net "M_A_CPU0_SA_DQ<29>")
	)
	(segment
		(start 313.870594 -281.053032)
		(end 313.843416 -281.041602)
		(width 0.1016)
		(layer "F.Cu")
		(net "M_A_CPU0_SA_DQ<29>")
	)
	(segment
		(start 331.530198 -266.307824)
		(end 324.264782 -273.57324)
		(width 0.1016)
		(layer "F.Cu")
		(net "M_A_CPU0_SA_DQ<29>")
	)
	(segment
		(start 321.792346 -279.122124)
		(end 321.046094 -279.122124)
		(width 0.1016)
		(layer "F.Cu")
		(net "M_A_CPU0_SA_DQ<29>")
	)
	(segment
		(start 333.629508 -265.376152)
		(end 333.347822 -265.376152)
		(width 0.088646)
		(layer "F.Cu")
		(net "M_A_CPU0_SA_DQ<29>")
	)
	(segment
		(start 331.842872 -265.550396)
		(end 331.651356 -265.550396)
		(width 0.1016)
		(layer "F.Cu")
		(net "M_A_CPU0_SA_DQ<29>")
	)
	(segment
		(start 333.845662 -265.592306)
		(end 333.629508 -265.376152)
		(width 0.088646)
		(layer "F.Cu")
		(net "M_A_CPU0_SA_DQ<29>")
	)
	(segment
		(start 333.243174 -265.83005)
		(end 333.093314 -265.91641)
		(width 0.088646)
		(layer "F.Cu")
		(net "M_A_CPU0_SA_DQ<29>")
	)
	(segment
		(start 307.17617 -280.61666)
		(end 308.887114 -280.61666)
		(width 0.20066)
		(layer "F.Cu")
		(net "M_A_CPU0_SA_DQ<29>")
	)
	(segment
		(start 302.356774 -280.831544)
		(end 302.805846 -280.831544)
		(width 0.20066)
		(layer "F.Cu")
		(net "M_A_CPU0_SA_DQ<29>")
	)
	(segment
		(start 306.644294 -280.191718)
		(end 306.751228 -280.191718)
		(width 0.20066)
		(layer "F.Cu")
		(net "M_A_CPU0_SA_DQ<29>")
	)
	(segment
		(start 311.395618 -280.887678)
		(end 311.395618 -280.179272)
		(width 0.20066)
		(layer "F.Cu")
		(net "M_A_CPU0_SA_DQ<29>")
	)
	(segment
		(start 311.570116 -281.062176)
		(end 311.395618 -280.887678)
		(width 0.20066)
		(layer "F.Cu")
		(net "M_A_CPU0_SA_DQ<29>")
	)
	(segment
		(start 304.319178 -280.172668)
		(end 304.338228 -280.191718)
		(width 0.101854)
		(layer "F.Cu")
		(net "M_A_CPU0_SA_DQ<29>")
	)
	(segment
		(start 332.072742 -265.550396)
		(end 331.842872 -265.550396)
		(width 0.088646)
		(layer "F.Cu")
		(net "M_A_CPU0_SA_DQ<29>")
	)
	(segment
		(start 301.343314 -280.61666)
		(end 302.14189 -280.61666)
		(width 0.20066)
		(layer "F.Cu")
		(net "M_A_CPU0_SA_DQ<29>")
	)
	(segment
		(start 314.15228 -281.053032)
		(end 313.870594 -281.053032)
		(width 0.101854)
		(layer "F.Cu")
		(net "M_A_CPU0_SA_DQ<29>")
	)
	(segment
		(start 331.651356 -265.550396)
		(end 331.530198 -265.671554)
		(width 0.1016)
		(layer "F.Cu")
		(net "M_A_CPU0_SA_DQ<29>")
	)
	(segment
		(start 332.17739 -265.59383)
		(end 332.072742 -265.550396)
		(width 0.088646)
		(layer "F.Cu")
		(net "M_A_CPU0_SA_DQ<29>")
	)
	(segment
		(start 302.14189 -280.61666)
		(end 302.356774 -280.831544)
		(width 0.20066)
		(layer "F.Cu")
		(net "M_A_CPU0_SA_DQ<29>")
	)
	(segment
		(start 319.35293 -280.815288)
		(end 314.555378 -280.815288)
		(width 0.20066)
		(layer "F.Cu")
		(net "M_A_CPU0_SA_DQ<29>")
	)
	(segment
		(start 312.12536 -281.041602)
		(end 312.066178 -281.062176)
		(width 0.1016)
		(layer "F.Cu")
		(net "M_A_CPU0_SA_DQ<29>")
	)
	(segment
		(start 311.91708 -281.062176)
		(end 311.570116 -281.062176)
		(width 0.20066)
		(layer "F.Cu")
		(net "M_A_CPU0_SA_DQ<29>")
	)
	(segment
		(start 322.759832 -276.38883)
		(end 322.321174 -278.593296)
		(width 0.1016)
		(layer "F.Cu")
		(net "M_A_CPU0_SA_DQ<29>")
	)
	(segment
		(start 322.321174 -278.593296)
		(end 321.792346 -279.122124)
		(width 0.1016)
		(layer "F.Cu")
		(net "M_A_CPU0_SA_DQ<29>")
	)
	(segment
		(start 324.264782 -273.57324)
		(end 322.759832 -276.38883)
		(width 0.1016)
		(layer "F.Cu")
		(net "M_A_CPU0_SA_DQ<29>")
	)
	(segment
		(start 333.347822 -265.376152)
		(end 333.243174 -265.4808)
		(width 0.088646)
		(layer "F.Cu")
		(net "M_A_CPU0_SA_DQ<29>")
	)
	(segment
		(start 302.973232 -280.664158)
		(end 302.973232 -280.334974)
		(width 0.20066)
		(layer "F.Cu")
		(net "M_A_CPU0_SA_DQ<29>")
	)
	(arc
		(start 333.093314 -265.91641)
		(mid 332.999944 -265.955368)
		(end 332.899766 -265.969496)
		(width 0.088646)
		(layer "F.Cu")
		(net "M_A_CPU0_SA_DQ<29>")
	)
	(segment
		(start 333.01686 -266.405868)
		(end 333.375762 -266.405868)
		(width 0.088646)
		(layer "F.Cu")
		(net "M_A_CPU0_SA_DQ<28>")
	)
	(segment
		(start 304.319178 -281.874214)
		(end 304.324258 -281.874214)
		(width 0.101854)
		(layer "F.Cu")
		(net "M_A_CPU0_SA_DQ<28>")
	)
	(segment
		(start 312.116216 -281.89174)
		(end 313.79541 -281.89174)
		(width 0.1016)
		(layer "F.Cu")
		(net "M_A_CPU0_SA_DQ<28>")
	)
	(segment
		(start 314.386722 -281.882088)
		(end 314.560204 -281.95397)
		(width 0.20066)
		(layer "F.Cu")
		(net "M_A_CPU0_SA_DQ<28>")
	)
	(segment
		(start 309.385208 -282.316682)
		(end 309.766208 -281.935682)
		(width 0.20066)
		(layer "F.Cu")
		(net "M_A_CPU0_SA_DQ<28>")
	)
	(segment
		(start 331.82179 -266.975336)
		(end 332.00975 -266.787376)
		(width 0.088646)
		(layer "F.Cu")
		(net "M_A_CPU0_SA_DQ<28>")
	)
	(segment
		(start 322.45046 -279.660604)
		(end 322.45046 -279.550876)
		(width 0.1016)
		(layer "F.Cu")
		(net "M_A_CPU0_SA_DQ<28>")
	)
	(segment
		(start 306.58308 -281.89174)
		(end 306.644294 -281.89174)
		(width 0.101854)
		(layer "F.Cu")
		(net "M_A_CPU0_SA_DQ<28>")
	)
	(segment
		(start 307.564536 -282.316682)
		(end 308.887114 -282.316682)
		(width 0.20066)
		(layer "F.Cu")
		(net "M_A_CPU0_SA_DQ<28>")
	)
	(segment
		(start 332.407768 -266.424664)
		(end 332.478126 -266.495022)
		(width 0.088646)
		(layer "F.Cu")
		(net "M_A_CPU0_SA_DQ<28>")
	)
	(segment
		(start 311.89168 -281.884882)
		(end 312.094372 -281.884882)
		(width 0.101854)
		(layer "F.Cu")
		(net "M_A_CPU0_SA_DQ<28>")
	)
	(segment
		(start 309.766208 -281.935682)
		(end 310.195722 -281.935682)
		(width 0.20066)
		(layer "F.Cu")
		(net "M_A_CPU0_SA_DQ<28>")
	)
	(segment
		(start 314.560204 -281.95397)
		(end 314.669932 -282.063698)
		(width 0.20066)
		(layer "F.Cu")
		(net "M_A_CPU0_SA_DQ<28>")
	)
	(segment
		(start 317.782702 -282.578048)
		(end 318.066928 -282.578048)
		(width 0.20066)
		(layer "F.Cu")
		(net "M_A_CPU0_SA_DQ<28>")
	)
	(segment
		(start 318.203326 -282.714446)
		(end 319.264538 -282.714446)
		(width 0.20066)
		(layer "F.Cu")
		(net "M_A_CPU0_SA_DQ<28>")
	)
	(segment
		(start 311.462928 -281.884882)
		(end 311.89168 -281.884882)
		(width 0.20066)
		(layer "F.Cu")
		(net "M_A_CPU0_SA_DQ<28>")
	)
	(segment
		(start 318.066928 -282.578048)
		(end 318.203326 -282.714446)
		(width 0.20066)
		(layer "F.Cu")
		(net "M_A_CPU0_SA_DQ<28>")
	)
	(segment
		(start 310.472074 -282.302458)
		(end 310.805068 -282.495498)
		(width 0.20066)
		(layer "F.Cu")
		(net "M_A_CPU0_SA_DQ<28>")
	)
	(segment
		(start 323.340476 -276.597364)
		(end 324.761606 -273.939762)
		(width 0.1016)
		(layer "F.Cu")
		(net "M_A_CPU0_SA_DQ<28>")
	)
	(segment
		(start 332.98384 -266.372848)
		(end 333.01686 -266.405868)
		(width 0.088646)
		(layer "F.Cu")
		(net "M_A_CPU0_SA_DQ<28>")
	)
	(segment
		(start 306.644294 -281.89174)
		(end 307.139594 -281.89174)
		(width 0.20066)
		(layer "F.Cu")
		(net "M_A_CPU0_SA_DQ<28>")
	)
	(segment
		(start 322.53428 -280.076656)
		(end 322.53428 -279.744424)
		(width 0.1016)
		(layer "F.Cu")
		(net "M_A_CPU0_SA_DQ<28>")
	)
	(segment
		(start 316.642496 -282.585414)
		(end 316.922912 -282.86583)
		(width 0.20066)
		(layer "F.Cu")
		(net "M_A_CPU0_SA_DQ<28>")
	)
	(segment
		(start 302.188626 -282.316682)
		(end 302.396398 -282.524454)
		(width 0.20066)
		(layer "F.Cu")
		(net "M_A_CPU0_SA_DQ<28>")
	)
	(segment
		(start 316.922912 -282.86583)
		(end 317.49492 -282.86583)
		(width 0.20066)
		(layer "F.Cu")
		(net "M_A_CPU0_SA_DQ<28>")
	)
	(segment
		(start 303.002188 -281.874214)
		(end 304.319178 -281.874214)
		(width 0.20066)
		(layer "F.Cu")
		(net "M_A_CPU0_SA_DQ<28>")
	)
	(segment
		(start 302.898302 -282.318206)
		(end 302.898302 -281.9781)
		(width 0.20066)
		(layer "F.Cu")
		(net "M_A_CPU0_SA_DQ<28>")
	)
	(segment
		(start 322.196968 -280.253694)
		(end 322.357242 -280.253694)
		(width 0.1016)
		(layer "F.Cu")
		(net "M_A_CPU0_SA_DQ<28>")
	)
	(segment
		(start 310.805068 -282.495498)
		(end 311.081928 -282.421838)
		(width 0.20066)
		(layer "F.Cu")
		(net "M_A_CPU0_SA_DQ<28>")
	)
	(segment
		(start 322.45046 -279.550876)
		(end 322.828158 -279.173178)
		(width 0.1016)
		(layer "F.Cu")
		(net "M_A_CPU0_SA_DQ<28>")
	)
	(segment
		(start 316.358524 -282.585414)
		(end 316.642496 -282.585414)
		(width 0.20066)
		(layer "F.Cu")
		(net "M_A_CPU0_SA_DQ<28>")
	)
	(segment
		(start 321.772534 -280.20645)
		(end 321.88912 -280.089864)
		(width 0.1016)
		(layer "F.Cu")
		(net "M_A_CPU0_SA_DQ<28>")
	)
	(segment
		(start 322.033138 -280.089864)
		(end 322.196968 -280.253694)
		(width 0.1016)
		(layer "F.Cu")
		(net "M_A_CPU0_SA_DQ<28>")
	)
	(segment
		(start 322.828158 -279.173178)
		(end 323.340476 -276.597364)
		(width 0.1016)
		(layer "F.Cu")
		(net "M_A_CPU0_SA_DQ<28>")
	)
	(segment
		(start 315.144404 -282.89123)
		(end 316.052708 -282.89123)
		(width 0.20066)
		(layer "F.Cu")
		(net "M_A_CPU0_SA_DQ<28>")
	)
	(segment
		(start 312.094372 -281.884882)
		(end 312.116216 -281.89174)
		(width 0.1016)
		(layer "F.Cu")
		(net "M_A_CPU0_SA_DQ<28>")
	)
	(segment
		(start 302.692054 -282.524454)
		(end 302.898302 -282.318206)
		(width 0.20066)
		(layer "F.Cu")
		(net "M_A_CPU0_SA_DQ<28>")
	)
	(segment
		(start 331.726032 -266.975336)
		(end 331.82179 -266.975336)
		(width 0.088646)
		(layer "F.Cu")
		(net "M_A_CPU0_SA_DQ<28>")
	)
	(segment
		(start 311.380632 -281.906726)
		(end 311.462928 -281.884882)
		(width 0.20066)
		(layer "F.Cu")
		(net "M_A_CPU0_SA_DQ<28>")
	)
	(segment
		(start 307.139594 -281.89174)
		(end 307.564536 -282.316682)
		(width 0.20066)
		(layer "F.Cu")
		(net "M_A_CPU0_SA_DQ<28>")
	)
	(segment
		(start 302.396398 -282.524454)
		(end 302.692054 -282.524454)
		(width 0.20066)
		(layer "F.Cu")
		(net "M_A_CPU0_SA_DQ<28>")
	)
	(segment
		(start 324.761606 -273.939762)
		(end 331.331316 -267.370052)
		(width 0.1016)
		(layer "F.Cu")
		(net "M_A_CPU0_SA_DQ<28>")
	)
	(segment
		(start 311.081928 -282.421838)
		(end 311.380632 -281.906726)
		(width 0.20066)
		(layer "F.Cu")
		(net "M_A_CPU0_SA_DQ<28>")
	)
	(segment
		(start 304.605182 -281.89174)
		(end 306.58308 -281.89174)
		(width 0.1016)
		(layer "F.Cu")
		(net "M_A_CPU0_SA_DQ<28>")
	)
	(segment
		(start 322.53428 -279.744424)
		(end 322.45046 -279.660604)
		(width 0.1016)
		(layer "F.Cu")
		(net "M_A_CPU0_SA_DQ<28>")
	)
	(segment
		(start 317.49492 -282.86583)
		(end 317.782702 -282.578048)
		(width 0.20066)
		(layer "F.Cu")
		(net "M_A_CPU0_SA_DQ<28>")
	)
	(segment
		(start 332.00975 -266.697206)
		(end 332.282292 -266.424664)
		(width 0.088646)
		(layer "F.Cu")
		(net "M_A_CPU0_SA_DQ<28>")
	)
	(segment
		(start 332.282292 -266.424664)
		(end 332.407768 -266.424664)
		(width 0.088646)
		(layer "F.Cu")
		(net "M_A_CPU0_SA_DQ<28>")
	)
	(segment
		(start 304.341784 -281.89174)
		(end 304.605182 -281.89174)
		(width 0.101854)
		(layer "F.Cu")
		(net "M_A_CPU0_SA_DQ<28>")
	)
	(segment
		(start 310.195722 -281.935682)
		(end 310.420766 -282.10891)
		(width 0.20066)
		(layer "F.Cu")
		(net "M_A_CPU0_SA_DQ<28>")
	)
	(segment
		(start 322.357242 -280.253694)
		(end 322.53428 -280.076656)
		(width 0.1016)
		(layer "F.Cu")
		(net "M_A_CPU0_SA_DQ<28>")
	)
	(segment
		(start 314.10148 -281.882088)
		(end 314.386722 -281.882088)
		(width 0.20066)
		(layer "F.Cu")
		(net "M_A_CPU0_SA_DQ<28>")
	)
	(segment
		(start 304.324258 -281.874214)
		(end 304.341784 -281.89174)
		(width 0.101854)
		(layer "F.Cu")
		(net "M_A_CPU0_SA_DQ<28>")
	)
	(segment
		(start 314.917582 -282.664408)
		(end 315.144404 -282.89123)
		(width 0.20066)
		(layer "F.Cu")
		(net "M_A_CPU0_SA_DQ<28>")
	)
	(segment
		(start 331.331316 -267.370052)
		(end 331.726032 -266.975336)
		(width 0.088646)
		(layer "F.Cu")
		(net "M_A_CPU0_SA_DQ<28>")
	)
	(segment
		(start 314.669932 -282.063698)
		(end 314.84062 -282.477718)
		(width 0.20066)
		(layer "F.Cu")
		(net "M_A_CPU0_SA_DQ<28>")
	)
	(segment
		(start 332.478126 -266.495022)
		(end 332.697582 -266.495022)
		(width 0.088646)
		(layer "F.Cu")
		(net "M_A_CPU0_SA_DQ<28>")
	)
	(segment
		(start 319.264538 -282.714446)
		(end 321.772534 -280.20645)
		(width 0.20066)
		(layer "F.Cu")
		(net "M_A_CPU0_SA_DQ<28>")
	)
	(segment
		(start 332.819756 -266.372848)
		(end 332.98384 -266.372848)
		(width 0.088646)
		(layer "F.Cu")
		(net "M_A_CPU0_SA_DQ<28>")
	)
	(segment
		(start 302.898302 -281.9781)
		(end 303.002188 -281.874214)
		(width 0.20066)
		(layer "F.Cu")
		(net "M_A_CPU0_SA_DQ<28>")
	)
	(segment
		(start 314.84062 -282.477718)
		(end 314.917582 -282.664408)
		(width 0.20066)
		(layer "F.Cu")
		(net "M_A_CPU0_SA_DQ<28>")
	)
	(segment
		(start 316.052708 -282.89123)
		(end 316.358524 -282.585414)
		(width 0.20066)
		(layer "F.Cu")
		(net "M_A_CPU0_SA_DQ<28>")
	)
	(segment
		(start 332.00975 -266.787376)
		(end 332.00975 -266.697206)
		(width 0.088646)
		(layer "F.Cu")
		(net "M_A_CPU0_SA_DQ<28>")
	)
	(segment
		(start 301.343314 -282.316682)
		(end 302.188626 -282.316682)
		(width 0.20066)
		(layer "F.Cu")
		(net "M_A_CPU0_SA_DQ<28>")
	)
	(segment
		(start 332.697582 -266.495022)
		(end 332.819756 -266.372848)
		(width 0.088646)
		(layer "F.Cu")
		(net "M_A_CPU0_SA_DQ<28>")
	)
	(segment
		(start 321.88912 -280.089864)
		(end 322.033138 -280.089864)
		(width 0.1016)
		(layer "F.Cu")
		(net "M_A_CPU0_SA_DQ<28>")
	)
	(segment
		(start 310.420766 -282.10891)
		(end 310.472074 -282.302458)
		(width 0.20066)
		(layer "F.Cu")
		(net "M_A_CPU0_SA_DQ<28>")
	)
	(segment
		(start 308.887114 -282.316682)
		(end 309.385208 -282.316682)
		(width 0.20066)
		(layer "F.Cu")
		(net "M_A_CPU0_SA_DQ<28>")
	)
	(segment
		(start 313.79541 -281.89174)
		(end 313.838336 -281.882088)
		(width 0.1016)
		(layer "F.Cu")
		(net "M_A_CPU0_SA_DQ<28>")
	)
	(segment
		(start 313.838336 -281.882088)
		(end 314.10148 -281.882088)
		(width 0.101854)
		(layer "F.Cu")
		(net "M_A_CPU0_SA_DQ<28>")
	)
	(segment
		(start 324.832218 -277.075138)
		(end 323.909944 -281.709876)
		(width 0.1016)
		(layer "F.Cu")
		(net "M_A_CPU0_SA_DQ<27>")
	)
	(segment
		(start 312.394092 -285.716472)
		(end 312.394346 -285.716726)
		(width 0.20066)
		(layer "F.Cu")
		(net "M_A_CPU0_SA_DQ<27>")
	)
	(segment
		(start 335.601056 -267.64615)
		(end 335.227676 -267.64615)
		(width 0.088646)
		(layer "F.Cu")
		(net "M_A_CPU0_SA_DQ<27>")
	)
	(segment
		(start 333.238348 -267.657326)
		(end 332.99146 -267.814806)
		(width 0.088646)
		(layer "F.Cu")
		(net "M_A_CPU0_SA_DQ<27>")
	)
	(segment
		(start 335.689702 -267.945108)
		(end 335.689702 -267.734796)
		(width 0.088646)
		(layer "F.Cu")
		(net "M_A_CPU0_SA_DQ<27>")
	)
	(segment
		(start 310.486552 -286.16021)
		(end 310.650128 -285.996634)
		(width 0.20066)
		(layer "F.Cu")
		(net "M_A_CPU0_SA_DQ<27>")
	)
	(segment
		(start 320.105024 -285.911544)
		(end 319.856104 -285.911544)
		(width 0.20066)
		(layer "F.Cu")
		(net "M_A_CPU0_SA_DQ<27>")
	)
	(segment
		(start 310.650128 -285.996634)
		(end 310.650128 -285.744666)
		(width 0.20066)
		(layer "F.Cu")
		(net "M_A_CPU0_SA_DQ<27>")
	)
	(segment
		(start 323.909944 -281.709876)
		(end 323.793104 -281.826716)
		(width 0.1016)
		(layer "F.Cu")
		(net "M_A_CPU0_SA_DQ<27>")
	)
	(segment
		(start 309.821326 -286.16021)
		(end 310.088026 -286.16021)
		(width 0.101854)
		(layer "F.Cu")
		(net "M_A_CPU0_SA_DQ<27>")
	)
	(segment
		(start 311.066434 -285.599124)
		(end 311.411112 -285.943802)
		(width 0.20066)
		(layer "F.Cu")
		(net "M_A_CPU0_SA_DQ<27>")
	)
	(segment
		(start 323.793104 -282.142946)
		(end 323.890894 -282.240736)
		(width 0.1016)
		(layer "F.Cu")
		(net "M_A_CPU0_SA_DQ<27>")
	)
	(segment
		(start 312.394346 -285.716726)
		(end 312.987182 -285.716726)
		(width 0.20066)
		(layer "F.Cu")
		(net "M_A_CPU0_SA_DQ<27>")
	)
	(segment
		(start 323.793104 -281.826716)
		(end 323.793104 -282.142946)
		(width 0.1016)
		(layer "F.Cu")
		(net "M_A_CPU0_SA_DQ<27>")
	)
	(segment
		(start 335.068164 -267.709396)
		(end 335.053432 -267.718032)
		(width 0.088646)
		(layer "F.Cu")
		(net "M_A_CPU0_SA_DQ<27>")
	)
	(segment
		(start 335.255362 -268.033754)
		(end 335.601056 -268.033754)
		(width 0.088646)
		(layer "F.Cu")
		(net "M_A_CPU0_SA_DQ<27>")
	)
	(segment
		(start 313.88939 -286.009842)
		(end 313.741308 -286.009842)
		(width 0.20066)
		(layer "F.Cu")
		(net "M_A_CPU0_SA_DQ<27>")
	)
	(segment
		(start 332.922372 -267.883894)
		(end 332.922372 -268.095476)
		(width 0.088646)
		(layer "F.Cu")
		(net "M_A_CPU0_SA_DQ<27>")
	)
	(segment
		(start 306.913534 -285.716726)
		(end 307.354478 -286.15767)
		(width 0.20066)
		(layer "F.Cu")
		(net "M_A_CPU0_SA_DQ<27>")
	)
	(segment
		(start 319.582038 -285.637478)
		(end 319.305686 -285.637478)
		(width 0.20066)
		(layer "F.Cu")
		(net "M_A_CPU0_SA_DQ<27>")
	)
	(segment
		(start 307.76291 -286.15767)
		(end 307.955188 -286.15767)
		(width 0.101854)
		(layer "F.Cu")
		(net "M_A_CPU0_SA_DQ<27>")
	)
	(segment
		(start 332.7527 -268.265148)
		(end 332.565756 -268.265148)
		(width 0.088646)
		(layer "F.Cu")
		(net "M_A_CPU0_SA_DQ<27>")
	)
	(segment
		(start 333.490316 -267.657326)
		(end 333.238348 -267.657326)
		(width 0.088646)
		(layer "F.Cu")
		(net "M_A_CPU0_SA_DQ<27>")
	)
	(segment
		(start 332.419198 -268.59865)
		(end 332.24597 -268.771878)
		(width 0.088646)
		(layer "F.Cu")
		(net "M_A_CPU0_SA_DQ<27>")
	)
	(segment
		(start 323.890894 -282.436316)
		(end 323.767958 -282.559252)
		(width 0.1016)
		(layer "F.Cu")
		(net "M_A_CPU0_SA_DQ<27>")
	)
	(segment
		(start 334.50276 -267.709396)
		(end 334.309974 -267.596366)
		(width 0.088646)
		(layer "F.Cu")
		(net "M_A_CPU0_SA_DQ<27>")
	)
	(segment
		(start 314.183776 -285.715456)
		(end 313.88939 -286.009842)
		(width 0.20066)
		(layer "F.Cu")
		(net "M_A_CPU0_SA_DQ<27>")
	)
	(segment
		(start 313.447684 -285.716726)
		(end 312.987182 -285.716726)
		(width 0.20066)
		(layer "F.Cu")
		(net "M_A_CPU0_SA_DQ<27>")
	)
	(segment
		(start 314.540138 -285.911544)
		(end 314.34405 -285.715456)
		(width 0.20066)
		(layer "F.Cu")
		(net "M_A_CPU0_SA_DQ<27>")
	)
	(segment
		(start 332.922372 -268.095476)
		(end 332.7527 -268.265148)
		(width 0.088646)
		(layer "F.Cu")
		(net "M_A_CPU0_SA_DQ<27>")
	)
	(segment
		(start 333.897986 -267.902182)
		(end 333.735172 -267.902182)
		(width 0.088646)
		(layer "F.Cu")
		(net "M_A_CPU0_SA_DQ<27>")
	)
	(segment
		(start 310.088026 -286.16021)
		(end 310.486552 -286.16021)
		(width 0.20066)
		(layer "F.Cu")
		(net "M_A_CPU0_SA_DQ<27>")
	)
	(segment
		(start 323.890894 -282.240736)
		(end 323.890894 -282.436316)
		(width 0.1016)
		(layer "F.Cu")
		(net "M_A_CPU0_SA_DQ<27>")
	)
	(segment
		(start 309.729124 -286.141668)
		(end 309.821326 -286.16021)
		(width 0.1016)
		(layer "F.Cu")
		(net "M_A_CPU0_SA_DQ<27>")
	)
	(segment
		(start 323.767958 -282.559252)
		(end 323.457316 -282.559252)
		(width 0.1016)
		(layer "F.Cu")
		(net "M_A_CPU0_SA_DQ<27>")
	)
	(segment
		(start 319.305686 -285.637478)
		(end 319.03162 -285.911544)
		(width 0.20066)
		(layer "F.Cu")
		(net "M_A_CPU0_SA_DQ<27>")
	)
	(segment
		(start 323.457316 -282.559252)
		(end 320.105024 -285.911544)
		(width 0.20066)
		(layer "F.Cu")
		(net "M_A_CPU0_SA_DQ<27>")
	)
	(segment
		(start 308.003448 -286.141668)
		(end 309.729124 -286.141668)
		(width 0.1016)
		(layer "F.Cu")
		(net "M_A_CPU0_SA_DQ<27>")
	)
	(segment
		(start 334.203802 -267.596366)
		(end 333.897986 -267.902182)
		(width 0.088646)
		(layer "F.Cu")
		(net "M_A_CPU0_SA_DQ<27>")
	)
	(segment
		(start 313.741308 -286.009842)
		(end 313.447938 -285.716472)
		(width 0.20066)
		(layer "F.Cu")
		(net "M_A_CPU0_SA_DQ<27>")
	)
	(segment
		(start 326.036432 -274.822412)
		(end 324.832218 -277.075138)
		(width 0.1016)
		(layer "F.Cu")
		(net "M_A_CPU0_SA_DQ<27>")
	)
	(segment
		(start 332.086966 -268.771878)
		(end 331.902054 -268.95679)
		(width 0.088646)
		(layer "F.Cu")
		(net "M_A_CPU0_SA_DQ<27>")
	)
	(segment
		(start 332.99146 -267.814806)
		(end 332.922372 -267.883894)
		(width 0.088646)
		(layer "F.Cu")
		(net "M_A_CPU0_SA_DQ<27>")
	)
	(segment
		(start 319.856104 -285.911544)
		(end 319.582038 -285.637478)
		(width 0.20066)
		(layer "F.Cu")
		(net "M_A_CPU0_SA_DQ<27>")
	)
	(segment
		(start 311.411112 -285.943802)
		(end 312.166762 -285.943802)
		(width 0.20066)
		(layer "F.Cu")
		(net "M_A_CPU0_SA_DQ<27>")
	)
	(segment
		(start 313.447938 -285.716472)
		(end 313.447684 -285.716726)
		(width 0.20066)
		(layer "F.Cu")
		(net "M_A_CPU0_SA_DQ<27>")
	)
	(segment
		(start 307.955188 -286.15767)
		(end 308.003448 -286.141668)
		(width 0.1016)
		(layer "F.Cu")
		(net "M_A_CPU0_SA_DQ<27>")
	)
	(segment
		(start 312.166762 -285.943802)
		(end 312.394092 -285.716472)
		(width 0.20066)
		(layer "F.Cu")
		(net "M_A_CPU0_SA_DQ<27>")
	)
	(segment
		(start 319.03162 -285.911544)
		(end 314.540138 -285.911544)
		(width 0.20066)
		(layer "F.Cu")
		(net "M_A_CPU0_SA_DQ<27>")
	)
	(segment
		(start 331.902054 -268.95679)
		(end 326.036432 -274.822412)
		(width 0.1016)
		(layer "F.Cu")
		(net "M_A_CPU0_SA_DQ<27>")
	)
	(segment
		(start 305.443382 -285.716726)
		(end 306.913534 -285.716726)
		(width 0.20066)
		(layer "F.Cu")
		(net "M_A_CPU0_SA_DQ<27>")
	)
	(segment
		(start 332.565756 -268.265148)
		(end 332.419198 -268.411706)
		(width 0.088646)
		(layer "F.Cu")
		(net "M_A_CPU0_SA_DQ<27>")
	)
	(segment
		(start 310.79567 -285.599124)
		(end 311.066434 -285.599124)
		(width 0.20066)
		(layer "F.Cu")
		(net "M_A_CPU0_SA_DQ<27>")
	)
	(segment
		(start 332.419198 -268.411706)
		(end 332.419198 -268.59865)
		(width 0.088646)
		(layer "F.Cu")
		(net "M_A_CPU0_SA_DQ<27>")
	)
	(segment
		(start 310.650128 -285.744666)
		(end 310.79567 -285.599124)
		(width 0.20066)
		(layer "F.Cu")
		(net "M_A_CPU0_SA_DQ<27>")
	)
	(segment
		(start 332.24597 -268.771878)
		(end 332.086966 -268.771878)
		(width 0.088646)
		(layer "F.Cu")
		(net "M_A_CPU0_SA_DQ<27>")
	)
	(segment
		(start 314.34405 -285.715456)
		(end 314.183776 -285.715456)
		(width 0.20066)
		(layer "F.Cu")
		(net "M_A_CPU0_SA_DQ<27>")
	)
	(segment
		(start 307.354478 -286.15767)
		(end 307.76291 -286.15767)
		(width 0.20066)
		(layer "F.Cu")
		(net "M_A_CPU0_SA_DQ<27>")
	)
	(segment
		(start 334.309974 -267.596366)
		(end 334.203802 -267.596366)
		(width 0.088646)
		(layer "F.Cu")
		(net "M_A_CPU0_SA_DQ<27>")
	)
	(segment
		(start 333.735172 -267.902182)
		(end 333.490316 -267.657326)
		(width 0.088646)
		(layer "F.Cu")
		(net "M_A_CPU0_SA_DQ<27>")
	)
	(arc
		(start 335.14157 -267.66774)
		(mid 335.104693 -267.688261)
		(end 335.068164 -267.709396)
		(width 0.088646)
		(layer "F.Cu")
		(net "M_A_CPU0_SA_DQ<27>")
	)
	(arc
		(start 335.227676 -267.64615)
		(mid 335.183273 -267.651565)
		(end 335.14157 -267.66774)
		(width 0.088646)
		(layer "F.Cu")
		(net "M_A_CPU0_SA_DQ<27>")
	)
	(arc
		(start 335.053432 -267.718032)
		(mid 334.776957 -267.785352)
		(end 334.50276 -267.709396)
		(width 0.088646)
		(layer "F.Cu")
		(net "M_A_CPU0_SA_DQ<27>")
	)
	(arc
		(start 335.601056 -268.033754)
		(mid 335.663738 -268.00779)
		(end 335.689702 -267.945108)
		(width 0.088646)
		(layer "F.Cu")
		(net "M_A_CPU0_SA_DQ<27>")
	)
	(arc
		(start 335.689702 -267.734796)
		(mid 335.663738 -267.672114)
		(end 335.601056 -267.64615)
		(width 0.088646)
		(layer "F.Cu")
		(net "M_A_CPU0_SA_DQ<27>")
	)
	(segment
		(start 314.89142 -287.416748)
		(end 312.987182 -287.416748)
		(width 0.20066)
		(layer "F.Cu")
		(net "M_A_CPU0_SA_DQ<26>")
	)
	(segment
		(start 326.53097 -275.190966)
		(end 325.412608 -277.283672)
		(width 0.1016)
		(layer "F.Cu")
		(net "M_A_CPU0_SA_DQ<26>")
	)
	(segment
		(start 307.991764 -286.983932)
		(end 308.016402 -286.991552)
		(width 0.1016)
		(layer "F.Cu")
		(net "M_A_CPU0_SA_DQ<26>")
	)
	(segment
		(start 335.10855 -268.958568)
		(end 335.10855 -269.217648)
		(width 0.088646)
		(layer "F.Cu")
		(net "M_A_CPU0_SA_DQ<26>")
	)
	(segment
		(start 305.443382 -287.416748)
		(end 306.708302 -287.416748)
		(width 0.20066)
		(layer "F.Cu")
		(net "M_A_CPU0_SA_DQ<26>")
	)
	(segment
		(start 335.10855 -269.217648)
		(end 334.948022 -269.378176)
		(width 0.088646)
		(layer "F.Cu")
		(net "M_A_CPU0_SA_DQ<26>")
	)
	(segment
		(start 333.720694 -268.228826)
		(end 333.517494 -268.432026)
		(width 0.088646)
		(layer "F.Cu")
		(net "M_A_CPU0_SA_DQ<26>")
	)
	(segment
		(start 311.135268 -287.551622)
		(end 311.270396 -287.416494)
		(width 0.20066)
		(layer "F.Cu")
		(net "M_A_CPU0_SA_DQ<26>")
	)
	(segment
		(start 334.785716 -268.84757)
		(end 334.997552 -268.84757)
		(width 0.088646)
		(layer "F.Cu")
		(net "M_A_CPU0_SA_DQ<26>")
	)
	(segment
		(start 333.517494 -268.432026)
		(end 333.361284 -268.432026)
		(width 0.088646)
		(layer "F.Cu")
		(net "M_A_CPU0_SA_DQ<26>")
	)
	(segment
		(start 310.662828 -287.118552)
		(end 310.662828 -287.404556)
		(width 0.20066)
		(layer "F.Cu")
		(net "M_A_CPU0_SA_DQ<26>")
	)
	(segment
		(start 323.948298 -283.888434)
		(end 320.604134 -287.232598)
		(width 0.20066)
		(layer "F.Cu")
		(net "M_A_CPU0_SA_DQ<26>")
	)
	(segment
		(start 334.948022 -269.378176)
		(end 334.54086 -269.378176)
		(width 0.088646)
		(layer "F.Cu")
		(net "M_A_CPU0_SA_DQ<26>")
	)
	(segment
		(start 333.234284 -268.559026)
		(end 333.234284 -268.891766)
		(width 0.088646)
		(layer "F.Cu")
		(net "M_A_CPU0_SA_DQ<26>")
	)
	(segment
		(start 310.52135 -286.977074)
		(end 310.662828 -287.118552)
		(width 0.20066)
		(layer "F.Cu")
		(net "M_A_CPU0_SA_DQ<26>")
	)
	(segment
		(start 310.071008 -286.977074)
		(end 310.088026 -286.977074)
		(width 0.101854)
		(layer "F.Cu")
		(net "M_A_CPU0_SA_DQ<26>")
	)
	(segment
		(start 306.82692 -287.124902)
		(end 306.96789 -286.983932)
		(width 0.20066)
		(layer "F.Cu")
		(net "M_A_CPU0_SA_DQ<26>")
	)
	(segment
		(start 311.270396 -287.416494)
		(end 311.27065 -287.416748)
		(width 0.20066)
		(layer "F.Cu")
		(net "M_A_CPU0_SA_DQ<26>")
	)
	(segment
		(start 306.82692 -287.29813)
		(end 306.82692 -287.124902)
		(width 0.20066)
		(layer "F.Cu")
		(net "M_A_CPU0_SA_DQ<26>")
	)
	(segment
		(start 333.234284 -268.891766)
		(end 333.107284 -269.018766)
		(width 0.088646)
		(layer "F.Cu")
		(net "M_A_CPU0_SA_DQ<26>")
	)
	(segment
		(start 324.500494 -281.867864)
		(end 324.500494 -283.336238)
		(width 0.1016)
		(layer "F.Cu")
		(net "M_A_CPU0_SA_DQ<26>")
	)
	(segment
		(start 333.361284 -268.432026)
		(end 333.234284 -268.559026)
		(width 0.088646)
		(layer "F.Cu")
		(net "M_A_CPU0_SA_DQ<26>")
	)
	(segment
		(start 310.809894 -287.551622)
		(end 311.135268 -287.551622)
		(width 0.20066)
		(layer "F.Cu")
		(net "M_A_CPU0_SA_DQ<26>")
	)
	(segment
		(start 334.54086 -269.378176)
		(end 334.292194 -269.12951)
		(width 0.088646)
		(layer "F.Cu")
		(net "M_A_CPU0_SA_DQ<26>")
	)
	(segment
		(start 320.604134 -287.232598)
		(end 315.07557 -287.232598)
		(width 0.20066)
		(layer "F.Cu")
		(net "M_A_CPU0_SA_DQ<26>")
	)
	(segment
		(start 332.70317 -269.018766)
		(end 331.9018 -269.820136)
		(width 0.088646)
		(layer "F.Cu")
		(net "M_A_CPU0_SA_DQ<26>")
	)
	(segment
		(start 311.27065 -287.416748)
		(end 312.987182 -287.416748)
		(width 0.20066)
		(layer "F.Cu")
		(net "M_A_CPU0_SA_DQ<26>")
	)
	(segment
		(start 307.76291 -286.983932)
		(end 307.991764 -286.983932)
		(width 0.101854)
		(layer "F.Cu")
		(net "M_A_CPU0_SA_DQ<26>")
	)
	(segment
		(start 306.708302 -287.416748)
		(end 306.82692 -287.29813)
		(width 0.20066)
		(layer "F.Cu")
		(net "M_A_CPU0_SA_DQ<26>")
	)
	(segment
		(start 315.07557 -287.232598)
		(end 314.89142 -287.416748)
		(width 0.20066)
		(layer "F.Cu")
		(net "M_A_CPU0_SA_DQ<26>")
	)
	(segment
		(start 334.997552 -268.84757)
		(end 335.10855 -268.958568)
		(width 0.088646)
		(layer "F.Cu")
		(net "M_A_CPU0_SA_DQ<26>")
	)
	(segment
		(start 334.292194 -269.12951)
		(end 334.292194 -268.571726)
		(width 0.088646)
		(layer "F.Cu")
		(net "M_A_CPU0_SA_DQ<26>")
	)
	(segment
		(start 331.9018 -269.820136)
		(end 326.53097 -275.190966)
		(width 0.1016)
		(layer "F.Cu")
		(net "M_A_CPU0_SA_DQ<26>")
	)
	(segment
		(start 333.107284 -269.018766)
		(end 332.70317 -269.018766)
		(width 0.088646)
		(layer "F.Cu")
		(net "M_A_CPU0_SA_DQ<26>")
	)
	(segment
		(start 324.500494 -283.336238)
		(end 323.948298 -283.888434)
		(width 0.1016)
		(layer "F.Cu")
		(net "M_A_CPU0_SA_DQ<26>")
	)
	(segment
		(start 325.412608 -277.283672)
		(end 324.500494 -281.867864)
		(width 0.1016)
		(layer "F.Cu")
		(net "M_A_CPU0_SA_DQ<26>")
	)
	(segment
		(start 310.05653 -286.991552)
		(end 310.071008 -286.977074)
		(width 0.101854)
		(layer "F.Cu")
		(net "M_A_CPU0_SA_DQ<26>")
	)
	(segment
		(start 334.292194 -268.571726)
		(end 333.949294 -268.228826)
		(width 0.088646)
		(layer "F.Cu")
		(net "M_A_CPU0_SA_DQ<26>")
	)
	(segment
		(start 310.088026 -286.977074)
		(end 310.52135 -286.977074)
		(width 0.20066)
		(layer "F.Cu")
		(net "M_A_CPU0_SA_DQ<26>")
	)
	(segment
		(start 310.662828 -287.404556)
		(end 310.809894 -287.551622)
		(width 0.20066)
		(layer "F.Cu")
		(net "M_A_CPU0_SA_DQ<26>")
	)
	(segment
		(start 308.016402 -286.991552)
		(end 310.05653 -286.991552)
		(width 0.1016)
		(layer "F.Cu")
		(net "M_A_CPU0_SA_DQ<26>")
	)
	(segment
		(start 333.949294 -268.228826)
		(end 333.720694 -268.228826)
		(width 0.088646)
		(layer "F.Cu")
		(net "M_A_CPU0_SA_DQ<26>")
	)
	(segment
		(start 306.96789 -286.983932)
		(end 307.76291 -286.983932)
		(width 0.20066)
		(layer "F.Cu")
		(net "M_A_CPU0_SA_DQ<26>")
	)
	(segment
		(start 333.25689 -268.033754)
		(end 333.375762 -268.033754)
		(width 0.088646)
		(layer "F.Cu")
		(net "M_A_CPU0_SA_DQ<25>")
	)
	(segment
		(start 304.319178 -286.127444)
		(end 304.376074 -286.127444)
		(width 0.101854)
		(layer "F.Cu")
		(net "M_A_CPU0_SA_DQ<25>")
	)
	(segment
		(start 308.887114 -286.56661)
		(end 311.080658 -286.56661)
		(width 0.20066)
		(layer "F.Cu")
		(net "M_A_CPU0_SA_DQ<25>")
	)
	(segment
		(start 301.967392 -286.566356)
		(end 302.21936 -286.818324)
		(width 0.20066)
		(layer "F.Cu")
		(net "M_A_CPU0_SA_DQ<25>")
	)
	(segment
		(start 311.92851 -287.006284)
		(end 311.943242 -286.991552)
		(width 0.101854)
		(layer "F.Cu")
		(net "M_A_CPU0_SA_DQ<25>")
	)
	(segment
		(start 311.520332 -287.006284)
		(end 311.862978 -287.006284)
		(width 0.20066)
		(layer "F.Cu")
		(net "M_A_CPU0_SA_DQ<25>")
	)
	(segment
		(start 314.188094 -286.991552)
		(end 314.25388 -286.991552)
		(width 0.20066)
		(layer "F.Cu")
		(net "M_A_CPU0_SA_DQ<25>")
	)
	(segment
		(start 311.862978 -287.006284)
		(end 311.92851 -287.006284)
		(width 0.101854)
		(layer "F.Cu")
		(net "M_A_CPU0_SA_DQ<25>")
	)
	(segment
		(start 307.180488 -286.56661)
		(end 308.887114 -286.56661)
		(width 0.20066)
		(layer "F.Cu")
		(net "M_A_CPU0_SA_DQ<25>")
	)
	(segment
		(start 304.390298 -286.141668)
		(end 306.63388 -286.141668)
		(width 0.1016)
		(layer "F.Cu")
		(net "M_A_CPU0_SA_DQ<25>")
	)
	(segment
		(start 331.686154 -269.60449)
		(end 333.25689 -268.033754)
		(width 0.088646)
		(layer "F.Cu")
		(net "M_A_CPU0_SA_DQ<25>")
	)
	(segment
		(start 325.12254 -277.179532)
		(end 326.283574 -275.00707)
		(width 0.1016)
		(layer "F.Cu")
		(net "M_A_CPU0_SA_DQ<25>")
	)
	(segment
		(start 306.63388 -286.141668)
		(end 306.644294 -286.141668)
		(width 0.101854)
		(layer "F.Cu")
		(net "M_A_CPU0_SA_DQ<25>")
	)
	(segment
		(start 324.03923 -282.882086)
		(end 324.195694 -282.504134)
		(width 0.1016)
		(layer "F.Cu")
		(net "M_A_CPU0_SA_DQ<25>")
	)
	(segment
		(start 323.49059 -283.430726)
		(end 324.03923 -282.882086)
		(width 0.1016)
		(layer "F.Cu")
		(net "M_A_CPU0_SA_DQ<25>")
	)
	(segment
		(start 301.967138 -286.56661)
		(end 301.967392 -286.566356)
		(width 0.20066)
		(layer "F.Cu")
		(net "M_A_CPU0_SA_DQ<25>")
	)
	(segment
		(start 314.387738 -286.93618)
		(end 314.772802 -286.551116)
		(width 0.20066)
		(layer "F.Cu")
		(net "M_A_CPU0_SA_DQ<25>")
	)
	(segment
		(start 303.006252 -286.127444)
		(end 304.319178 -286.127444)
		(width 0.20066)
		(layer "F.Cu")
		(net "M_A_CPU0_SA_DQ<25>")
	)
	(segment
		(start 301.343314 -286.56661)
		(end 301.967138 -286.56661)
		(width 0.20066)
		(layer "F.Cu")
		(net "M_A_CPU0_SA_DQ<25>")
	)
	(segment
		(start 306.644294 -286.141668)
		(end 306.755546 -286.141668)
		(width 0.20066)
		(layer "F.Cu")
		(net "M_A_CPU0_SA_DQ<25>")
	)
	(segment
		(start 302.837596 -286.2961)
		(end 303.006252 -286.127444)
		(width 0.20066)
		(layer "F.Cu")
		(net "M_A_CPU0_SA_DQ<25>")
	)
	(segment
		(start 302.603408 -286.818324)
		(end 302.837596 -286.584136)
		(width 0.20066)
		(layer "F.Cu")
		(net "M_A_CPU0_SA_DQ<25>")
	)
	(segment
		(start 306.755546 -286.141668)
		(end 307.180488 -286.56661)
		(width 0.20066)
		(layer "F.Cu")
		(net "M_A_CPU0_SA_DQ<25>")
	)
	(segment
		(start 311.080658 -286.56661)
		(end 311.520332 -287.006284)
		(width 0.20066)
		(layer "F.Cu")
		(net "M_A_CPU0_SA_DQ<25>")
	)
	(segment
		(start 324.195694 -281.837384)
		(end 325.12254 -277.179532)
		(width 0.1016)
		(layer "F.Cu")
		(net "M_A_CPU0_SA_DQ<25>")
	)
	(segment
		(start 314.25388 -286.991552)
		(end 314.387738 -286.93618)
		(width 0.20066)
		(layer "F.Cu")
		(net "M_A_CPU0_SA_DQ<25>")
	)
	(segment
		(start 324.195694 -282.504134)
		(end 324.195694 -281.837384)
		(width 0.1016)
		(layer "F.Cu")
		(net "M_A_CPU0_SA_DQ<25>")
	)
	(segment
		(start 302.21936 -286.818324)
		(end 302.603408 -286.818324)
		(width 0.20066)
		(layer "F.Cu")
		(net "M_A_CPU0_SA_DQ<25>")
	)
	(segment
		(start 302.837596 -286.584136)
		(end 302.837596 -286.2961)
		(width 0.20066)
		(layer "F.Cu")
		(net "M_A_CPU0_SA_DQ<25>")
	)
	(segment
		(start 314.772802 -286.551116)
		(end 320.3702 -286.551116)
		(width 0.20066)
		(layer "F.Cu")
		(net "M_A_CPU0_SA_DQ<25>")
	)
	(segment
		(start 320.3702 -286.551116)
		(end 323.49059 -283.430726)
		(width 0.20066)
		(layer "F.Cu")
		(net "M_A_CPU0_SA_DQ<25>")
	)
	(segment
		(start 311.943242 -286.991552)
		(end 314.188094 -286.991552)
		(width 0.1016)
		(layer "F.Cu")
		(net "M_A_CPU0_SA_DQ<25>")
	)
	(segment
		(start 304.376074 -286.127444)
		(end 304.390298 -286.141668)
		(width 0.101854)
		(layer "F.Cu")
		(net "M_A_CPU0_SA_DQ<25>")
	)
	(segment
		(start 326.283574 -275.00707)
		(end 331.686154 -269.60449)
		(width 0.1016)
		(layer "F.Cu")
		(net "M_A_CPU0_SA_DQ<25>")
	)
	(segment
		(start 324.805294 -281.90063)
		(end 324.805294 -283.936694)
		(width 0.1016)
		(layer "F.Cu")
		(net "M_A_CPU0_SA_DQ<24>")
	)
	(segment
		(start 325.703438 -277.386288)
		(end 324.805294 -281.90063)
		(width 0.1016)
		(layer "F.Cu")
		(net "M_A_CPU0_SA_DQ<24>")
	)
	(segment
		(start 302.837596 -287.996122)
		(end 303.007522 -287.826196)
		(width 0.20066)
		(layer "F.Cu")
		(net "M_A_CPU0_SA_DQ<24>")
	)
	(segment
		(start 324.400926 -284.341062)
		(end 320.85915 -287.882838)
		(width 0.20066)
		(layer "F.Cu")
		(net "M_A_CPU0_SA_DQ<24>")
	)
	(segment
		(start 306.644294 -287.826958)
		(end 307.023516 -287.826958)
		(width 0.20066)
		(layer "F.Cu")
		(net "M_A_CPU0_SA_DQ<24>")
	)
	(segment
		(start 302.21936 -288.518346)
		(end 302.603408 -288.518346)
		(width 0.20066)
		(layer "F.Cu")
		(net "M_A_CPU0_SA_DQ<24>")
	)
	(segment
		(start 304.389028 -287.826196)
		(end 304.404522 -287.84169)
		(width 0.101854)
		(layer "F.Cu")
		(net "M_A_CPU0_SA_DQ<24>")
	)
	(segment
		(start 311.64149 -287.82137)
		(end 310.968898 -288.049462)
		(width 0.20066)
		(layer "F.Cu")
		(net "M_A_CPU0_SA_DQ<24>")
	)
	(segment
		(start 312.067448 -287.84169)
		(end 312.047128 -287.82137)
		(width 0.101854)
		(layer "F.Cu")
		(net "M_A_CPU0_SA_DQ<24>")
	)
	(segment
		(start 333.845662 -268.84757)
		(end 333.440786 -269.252446)
		(width 0.088646)
		(layer "F.Cu")
		(net "M_A_CPU0_SA_DQ<24>")
	)
	(segment
		(start 333.440786 -269.252446)
		(end 332.900782 -269.252446)
		(width 0.088646)
		(layer "F.Cu")
		(net "M_A_CPU0_SA_DQ<24>")
	)
	(segment
		(start 306.624482 -287.826958)
		(end 306.644294 -287.826958)
		(width 0.101854)
		(layer "F.Cu")
		(net "M_A_CPU0_SA_DQ<24>")
	)
	(segment
		(start 315.281818 -288.06267)
		(end 314.523628 -288.06267)
		(width 0.20066)
		(layer "F.Cu")
		(net "M_A_CPU0_SA_DQ<24>")
	)
	(segment
		(start 332.117446 -270.035782)
		(end 326.778366 -275.374862)
		(width 0.1016)
		(layer "F.Cu")
		(net "M_A_CPU0_SA_DQ<24>")
	)
	(segment
		(start 315.46165 -287.882838)
		(end 315.281818 -288.06267)
		(width 0.20066)
		(layer "F.Cu")
		(net "M_A_CPU0_SA_DQ<24>")
	)
	(segment
		(start 314.17768 -287.84169)
		(end 312.067448 -287.84169)
		(width 0.1016)
		(layer "F.Cu")
		(net "M_A_CPU0_SA_DQ<24>")
	)
	(segment
		(start 324.805294 -283.936694)
		(end 324.400926 -284.341062)
		(width 0.1016)
		(layer "F.Cu")
		(net "M_A_CPU0_SA_DQ<24>")
	)
	(segment
		(start 306.60975 -287.84169)
		(end 306.624482 -287.826958)
		(width 0.101854)
		(layer "F.Cu")
		(net "M_A_CPU0_SA_DQ<24>")
	)
	(segment
		(start 309.974742 -288.266632)
		(end 308.887114 -288.266632)
		(width 0.20066)
		(layer "F.Cu")
		(net "M_A_CPU0_SA_DQ<24>")
	)
	(segment
		(start 326.778366 -275.374862)
		(end 325.703438 -277.386288)
		(width 0.1016)
		(layer "F.Cu")
		(net "M_A_CPU0_SA_DQ<24>")
	)
	(segment
		(start 301.967392 -288.266378)
		(end 302.21936 -288.518346)
		(width 0.20066)
		(layer "F.Cu")
		(net "M_A_CPU0_SA_DQ<24>")
	)
	(segment
		(start 307.46319 -288.266632)
		(end 308.887114 -288.266632)
		(width 0.20066)
		(layer "F.Cu")
		(net "M_A_CPU0_SA_DQ<24>")
	)
	(segment
		(start 303.007522 -287.826196)
		(end 304.319178 -287.826196)
		(width 0.20066)
		(layer "F.Cu")
		(net "M_A_CPU0_SA_DQ<24>")
	)
	(segment
		(start 312.047128 -287.82137)
		(end 311.89168 -287.82137)
		(width 0.101854)
		(layer "F.Cu")
		(net "M_A_CPU0_SA_DQ<24>")
	)
	(segment
		(start 310.968898 -288.049462)
		(end 309.974742 -288.266632)
		(width 0.20066)
		(layer "F.Cu")
		(net "M_A_CPU0_SA_DQ<24>")
	)
	(segment
		(start 311.89168 -287.82137)
		(end 311.64149 -287.82137)
		(width 0.20066)
		(layer "F.Cu")
		(net "M_A_CPU0_SA_DQ<24>")
	)
	(segment
		(start 304.404522 -287.84169)
		(end 306.60975 -287.84169)
		(width 0.1016)
		(layer "F.Cu")
		(net "M_A_CPU0_SA_DQ<24>")
	)
	(segment
		(start 314.302648 -287.84169)
		(end 314.17768 -287.84169)
		(width 0.20066)
		(layer "F.Cu")
		(net "M_A_CPU0_SA_DQ<24>")
	)
	(segment
		(start 302.837596 -288.284158)
		(end 302.837596 -287.996122)
		(width 0.20066)
		(layer "F.Cu")
		(net "M_A_CPU0_SA_DQ<24>")
	)
	(segment
		(start 314.523628 -288.06267)
		(end 314.302648 -287.84169)
		(width 0.20066)
		(layer "F.Cu")
		(net "M_A_CPU0_SA_DQ<24>")
	)
	(segment
		(start 332.900782 -269.252446)
		(end 332.117446 -270.035782)
		(width 0.088646)
		(layer "F.Cu")
		(net "M_A_CPU0_SA_DQ<24>")
	)
	(segment
		(start 307.023516 -287.826958)
		(end 307.46319 -288.266632)
		(width 0.20066)
		(layer "F.Cu")
		(net "M_A_CPU0_SA_DQ<24>")
	)
	(segment
		(start 301.967138 -288.266632)
		(end 301.967392 -288.266378)
		(width 0.20066)
		(layer "F.Cu")
		(net "M_A_CPU0_SA_DQ<24>")
	)
	(segment
		(start 302.603408 -288.518346)
		(end 302.837596 -288.284158)
		(width 0.20066)
		(layer "F.Cu")
		(net "M_A_CPU0_SA_DQ<24>")
	)
	(segment
		(start 304.319178 -287.826196)
		(end 304.389028 -287.826196)
		(width 0.101854)
		(layer "F.Cu")
		(net "M_A_CPU0_SA_DQ<24>")
	)
	(segment
		(start 301.343314 -288.266632)
		(end 301.967138 -288.266632)
		(width 0.20066)
		(layer "F.Cu")
		(net "M_A_CPU0_SA_DQ<24>")
	)
	(segment
		(start 320.85915 -287.882838)
		(end 315.46165 -287.882838)
		(width 0.20066)
		(layer "F.Cu")
		(net "M_A_CPU0_SA_DQ<24>")
	)
	(segment
		(start 333.249778 -270.018002)
		(end 332.838552 -270.429228)
		(width 0.088646)
		(layer "F.Cu")
		(net "M_A_CPU0_SA_DQ<23>")
	)
	(segment
		(start 334.574134 -270.001746)
		(end 334.482948 -270.092932)
		(width 0.088646)
		(layer "F.Cu")
		(net "M_A_CPU0_SA_DQ<23>")
	)
	(segment
		(start 334.482948 -270.273272)
		(end 334.39862 -270.3576)
		(width 0.088646)
		(layer "F.Cu")
		(net "M_A_CPU0_SA_DQ<23>")
	)
	(segment
		(start 307.814726 -289.541712)
		(end 310.03748 -289.541712)
		(width 0.1016)
		(layer "F.Cu")
		(net "M_A_CPU0_SA_DQ<23>")
	)
	(segment
		(start 313.563762 -289.11677)
		(end 312.987182 -289.11677)
		(width 0.20066)
		(layer "F.Cu")
		(net "M_A_CPU0_SA_DQ<23>")
	)
	(segment
		(start 334.19796 -270.30426)
		(end 334.19796 -270.095472)
		(width 0.088646)
		(layer "F.Cu")
		(net "M_A_CPU0_SA_DQ<23>")
	)
	(segment
		(start 333.665576 -269.862808)
		(end 333.510382 -270.018002)
		(width 0.088646)
		(layer "F.Cu")
		(net "M_A_CPU0_SA_DQ<23>")
	)
	(segment
		(start 307.128672 -289.11677)
		(end 307.128926 -289.116516)
		(width 0.20066)
		(layer "F.Cu")
		(net "M_A_CPU0_SA_DQ<23>")
	)
	(segment
		(start 322.652898 -288.882074)
		(end 322.652898 -289.166046)
		(width 0.20066)
		(layer "F.Cu")
		(net "M_A_CPU0_SA_DQ<23>")
	)
	(segment
		(start 314.731146 -289.094672)
		(end 314.292996 -289.532822)
		(width 0.20066)
		(layer "F.Cu")
		(net "M_A_CPU0_SA_DQ<23>")
	)
	(segment
		(start 324.44563 -287.373314)
		(end 324.161658 -287.373314)
		(width 0.20066)
		(layer "F.Cu")
		(net "M_A_CPU0_SA_DQ<23>")
	)
	(segment
		(start 323.658738 -287.876234)
		(end 323.658738 -288.160206)
		(width 0.20066)
		(layer "F.Cu")
		(net "M_A_CPU0_SA_DQ<23>")
	)
	(segment
		(start 324.296532 -285.702756)
		(end 324.038722 -285.960566)
		(width 0.20066)
		(layer "F.Cu")
		(net "M_A_CPU0_SA_DQ<23>")
	)
	(segment
		(start 310.088026 -289.541712)
		(end 310.370982 -289.541712)
		(width 0.20066)
		(layer "F.Cu")
		(net "M_A_CPU0_SA_DQ<23>")
	)
	(segment
		(start 333.510382 -270.018002)
		(end 333.249778 -270.018002)
		(width 0.088646)
		(layer "F.Cu")
		(net "M_A_CPU0_SA_DQ<23>")
	)
	(segment
		(start 322.027042 -287.972246)
		(end 322.027042 -288.256218)
		(width 0.20066)
		(layer "F.Cu")
		(net "M_A_CPU0_SA_DQ<23>")
	)
	(segment
		(start 323.032882 -287.250378)
		(end 323.658738 -287.876234)
		(width 0.20066)
		(layer "F.Cu")
		(net "M_A_CPU0_SA_DQ<23>")
	)
	(segment
		(start 332.838552 -270.429228)
		(end 332.61173 -270.429228)
		(width 0.088646)
		(layer "F.Cu")
		(net "M_A_CPU0_SA_DQ<23>")
	)
	(segment
		(start 334.785716 -270.079724)
		(end 334.707738 -270.001746)
		(width 0.088646)
		(layer "F.Cu")
		(net "M_A_CPU0_SA_DQ<23>")
	)
	(segment
		(start 325.51878 -281.44216)
		(end 325.51878 -285.739332)
		(width 0.1016)
		(layer "F.Cu")
		(net "M_A_CPU0_SA_DQ<23>")
	)
	(segment
		(start 310.03748 -289.541712)
		(end 310.088026 -289.541712)
		(width 0.101854)
		(layer "F.Cu")
		(net "M_A_CPU0_SA_DQ<23>")
	)
	(segment
		(start 310.715152 -288.95675)
		(end 311.191656 -288.95675)
		(width 0.20066)
		(layer "F.Cu")
		(net "M_A_CPU0_SA_DQ<23>")
	)
	(segment
		(start 307.407056 -289.554666)
		(end 307.76291 -289.554666)
		(width 0.20066)
		(layer "F.Cu")
		(net "M_A_CPU0_SA_DQ<23>")
	)
	(segment
		(start 311.351676 -289.11677)
		(end 312.987182 -289.11677)
		(width 0.20066)
		(layer "F.Cu")
		(net "M_A_CPU0_SA_DQ<23>")
	)
	(segment
		(start 322.149978 -289.384994)
		(end 321.536822 -288.771838)
		(width 0.20066)
		(layer "F.Cu")
		(net "M_A_CPU0_SA_DQ<23>")
	)
	(segment
		(start 325.176642 -286.08147)
		(end 324.916038 -286.08147)
		(width 0.20066)
		(layer "F.Cu")
		(net "M_A_CPU0_SA_DQ<23>")
	)
	(segment
		(start 307.128926 -289.116516)
		(end 307.25491 -289.2425)
		(width 0.20066)
		(layer "F.Cu")
		(net "M_A_CPU0_SA_DQ<23>")
	)
	(segment
		(start 310.519318 -289.393376)
		(end 310.519318 -289.152584)
		(width 0.20066)
		(layer "F.Cu")
		(net "M_A_CPU0_SA_DQ<23>")
	)
	(segment
		(start 322.652898 -289.166046)
		(end 322.43395 -289.384994)
		(width 0.20066)
		(layer "F.Cu")
		(net "M_A_CPU0_SA_DQ<23>")
	)
	(segment
		(start 334.19796 -270.095472)
		(end 333.965296 -269.862808)
		(width 0.088646)
		(layer "F.Cu")
		(net "M_A_CPU0_SA_DQ<23>")
	)
	(segment
		(start 323.032882 -286.966406)
		(end 323.032882 -287.250378)
		(width 0.20066)
		(layer "F.Cu")
		(net "M_A_CPU0_SA_DQ<23>")
	)
	(segment
		(start 333.965296 -269.862808)
		(end 333.665576 -269.862808)
		(width 0.088646)
		(layer "F.Cu")
		(net "M_A_CPU0_SA_DQ<23>")
	)
	(segment
		(start 315.514736 -289.094672)
		(end 314.731146 -289.094672)
		(width 0.20066)
		(layer "F.Cu")
		(net "M_A_CPU0_SA_DQ<23>")
	)
	(segment
		(start 324.038722 -285.960566)
		(end 324.038722 -286.244538)
		(width 0.20066)
		(layer "F.Cu")
		(net "M_A_CPU0_SA_DQ<23>")
	)
	(segment
		(start 307.25491 -289.2425)
		(end 307.25491 -289.40252)
		(width 0.20066)
		(layer "F.Cu")
		(net "M_A_CPU0_SA_DQ<23>")
	)
	(segment
		(start 322.24599 -287.753298)
		(end 322.027042 -287.972246)
		(width 0.20066)
		(layer "F.Cu")
		(net "M_A_CPU0_SA_DQ<23>")
	)
	(segment
		(start 324.038722 -286.244538)
		(end 324.664578 -286.870394)
		(width 0.20066)
		(layer "F.Cu")
		(net "M_A_CPU0_SA_DQ<23>")
	)
	(segment
		(start 310.519318 -289.152584)
		(end 310.715152 -288.95675)
		(width 0.20066)
		(layer "F.Cu")
		(net "M_A_CPU0_SA_DQ<23>")
	)
	(segment
		(start 313.980322 -289.532822)
		(end 313.564016 -289.116516)
		(width 0.20066)
		(layer "F.Cu")
		(net "M_A_CPU0_SA_DQ<23>")
	)
	(segment
		(start 323.43979 -288.379154)
		(end 323.155818 -288.379154)
		(width 0.20066)
		(layer "F.Cu")
		(net "M_A_CPU0_SA_DQ<23>")
	)
	(segment
		(start 334.785716 -270.475456)
		(end 334.785716 -270.079724)
		(width 0.088646)
		(layer "F.Cu")
		(net "M_A_CPU0_SA_DQ<23>")
	)
	(segment
		(start 314.292996 -289.532822)
		(end 313.980322 -289.532822)
		(width 0.20066)
		(layer "F.Cu")
		(net "M_A_CPU0_SA_DQ<23>")
	)
	(segment
		(start 307.801772 -289.554666)
		(end 307.814726 -289.541712)
		(width 0.101854)
		(layer "F.Cu")
		(net "M_A_CPU0_SA_DQ<23>")
	)
	(segment
		(start 326.297036 -277.542498)
		(end 325.51878 -281.44216)
		(width 0.1016)
		(layer "F.Cu")
		(net "M_A_CPU0_SA_DQ<23>")
	)
	(segment
		(start 334.482948 -270.092932)
		(end 334.482948 -270.273272)
		(width 0.088646)
		(layer "F.Cu")
		(net "M_A_CPU0_SA_DQ<23>")
	)
	(segment
		(start 327.217786 -275.82241)
		(end 326.297036 -277.542498)
		(width 0.1016)
		(layer "F.Cu")
		(net "M_A_CPU0_SA_DQ<23>")
	)
	(segment
		(start 324.916038 -286.08147)
		(end 324.537324 -285.702756)
		(width 0.20066)
		(layer "F.Cu")
		(net "M_A_CPU0_SA_DQ<23>")
	)
	(segment
		(start 334.707738 -270.001746)
		(end 334.574134 -270.001746)
		(width 0.088646)
		(layer "F.Cu")
		(net "M_A_CPU0_SA_DQ<23>")
	)
	(segment
		(start 324.537324 -285.702756)
		(end 324.296532 -285.702756)
		(width 0.20066)
		(layer "F.Cu")
		(net "M_A_CPU0_SA_DQ<23>")
	)
	(segment
		(start 313.564016 -289.116516)
		(end 313.563762 -289.11677)
		(width 0.20066)
		(layer "F.Cu")
		(net "M_A_CPU0_SA_DQ<23>")
	)
	(segment
		(start 324.161658 -287.373314)
		(end 323.535802 -286.747458)
		(width 0.20066)
		(layer "F.Cu")
		(net "M_A_CPU0_SA_DQ<23>")
	)
	(segment
		(start 323.658738 -288.160206)
		(end 323.43979 -288.379154)
		(width 0.20066)
		(layer "F.Cu")
		(net "M_A_CPU0_SA_DQ<23>")
	)
	(segment
		(start 321.536822 -288.771838)
		(end 315.83757 -288.771838)
		(width 0.20066)
		(layer "F.Cu")
		(net "M_A_CPU0_SA_DQ<23>")
	)
	(segment
		(start 323.535802 -286.747458)
		(end 323.25183 -286.747458)
		(width 0.20066)
		(layer "F.Cu")
		(net "M_A_CPU0_SA_DQ<23>")
	)
	(segment
		(start 332.61173 -270.429228)
		(end 332.396338 -270.64462)
		(width 0.088646)
		(layer "F.Cu")
		(net "M_A_CPU0_SA_DQ<23>")
	)
	(segment
		(start 322.529962 -287.753298)
		(end 322.24599 -287.753298)
		(width 0.20066)
		(layer "F.Cu")
		(net "M_A_CPU0_SA_DQ<23>")
	)
	(segment
		(start 324.664578 -287.154366)
		(end 324.44563 -287.373314)
		(width 0.20066)
		(layer "F.Cu")
		(net "M_A_CPU0_SA_DQ<23>")
	)
	(segment
		(start 332.032356 -271.008602)
		(end 327.217786 -275.82241)
		(width 0.1016)
		(layer "F.Cu")
		(net "M_A_CPU0_SA_DQ<23>")
	)
	(segment
		(start 323.25183 -286.747458)
		(end 323.032882 -286.966406)
		(width 0.20066)
		(layer "F.Cu")
		(net "M_A_CPU0_SA_DQ<23>")
	)
	(segment
		(start 323.155818 -288.379154)
		(end 322.529962 -287.753298)
		(width 0.20066)
		(layer "F.Cu")
		(net "M_A_CPU0_SA_DQ<23>")
	)
	(segment
		(start 334.2513 -270.3576)
		(end 334.19796 -270.30426)
		(width 0.088646)
		(layer "F.Cu")
		(net "M_A_CPU0_SA_DQ<23>")
	)
	(segment
		(start 322.027042 -288.256218)
		(end 322.652898 -288.882074)
		(width 0.20066)
		(layer "F.Cu")
		(net "M_A_CPU0_SA_DQ<23>")
	)
	(segment
		(start 315.83757 -288.771838)
		(end 315.514736 -289.094672)
		(width 0.20066)
		(layer "F.Cu")
		(net "M_A_CPU0_SA_DQ<23>")
	)
	(segment
		(start 324.664578 -286.870394)
		(end 324.664578 -287.154366)
		(width 0.20066)
		(layer "F.Cu")
		(net "M_A_CPU0_SA_DQ<23>")
	)
	(segment
		(start 334.39862 -270.3576)
		(end 334.2513 -270.3576)
		(width 0.088646)
		(layer "F.Cu")
		(net "M_A_CPU0_SA_DQ<23>")
	)
	(segment
		(start 310.370982 -289.541712)
		(end 310.519318 -289.393376)
		(width 0.20066)
		(layer "F.Cu")
		(net "M_A_CPU0_SA_DQ<23>")
	)
	(segment
		(start 322.43395 -289.384994)
		(end 322.149978 -289.384994)
		(width 0.20066)
		(layer "F.Cu")
		(net "M_A_CPU0_SA_DQ<23>")
	)
	(segment
		(start 332.396338 -270.64462)
		(end 332.032356 -271.008602)
		(width 0.1016)
		(layer "F.Cu")
		(net "M_A_CPU0_SA_DQ<23>")
	)
	(segment
		(start 305.443382 -289.11677)
		(end 307.128672 -289.11677)
		(width 0.20066)
		(layer "F.Cu")
		(net "M_A_CPU0_SA_DQ<23>")
	)
	(segment
		(start 307.76291 -289.554666)
		(end 307.801772 -289.554666)
		(width 0.101854)
		(layer "F.Cu")
		(net "M_A_CPU0_SA_DQ<23>")
	)
	(segment
		(start 325.51878 -285.739332)
		(end 325.417688 -285.840424)
		(width 0.1016)
		(layer "F.Cu")
		(net "M_A_CPU0_SA_DQ<23>")
	)
	(segment
		(start 325.417688 -285.840424)
		(end 325.176642 -286.08147)
		(width 0.20066)
		(layer "F.Cu")
		(net "M_A_CPU0_SA_DQ<23>")
	)
	(segment
		(start 307.25491 -289.40252)
		(end 307.407056 -289.554666)
		(width 0.20066)
		(layer "F.Cu")
		(net "M_A_CPU0_SA_DQ<23>")
	)
	(segment
		(start 311.191656 -288.95675)
		(end 311.351676 -289.11677)
		(width 0.20066)
		(layer "F.Cu")
		(net "M_A_CPU0_SA_DQ<23>")
	)
	(segment
		(start 335.255362 -271.289272)
		(end 335.255362 -270.809466)
		(width 0.088646)
		(layer "F.Cu")
		(net "M_A_CPU0_SA_DQ<22>")
	)
	(segment
		(start 335.181194 -270.735298)
		(end 335.064608 -270.735298)
		(width 0.088646)
		(layer "F.Cu")
		(net "M_A_CPU0_SA_DQ<22>")
	)
	(segment
		(start 314.710572 -290.915852)
		(end 313.980322 -290.915852)
		(width 0.20066)
		(layer "F.Cu")
		(net "M_A_CPU0_SA_DQ<22>")
	)
	(segment
		(start 307.17871 -290.371022)
		(end 307.76291 -290.371022)
		(width 0.20066)
		(layer "F.Cu")
		(net "M_A_CPU0_SA_DQ<22>")
	)
	(segment
		(start 333.920846 -271.153128)
		(end 333.734664 -271.153128)
		(width 0.088646)
		(layer "F.Cu")
		(net "M_A_CPU0_SA_DQ<22>")
	)
	(segment
		(start 332.294484 -271.609566)
		(end 332.062328 -271.841722)
		(width 0.1016)
		(layer "F.Cu")
		(net "M_A_CPU0_SA_DQ<22>")
	)
	(segment
		(start 319.806828 -290.6649)
		(end 319.496948 -290.6649)
		(width 0.20066)
		(layer "F.Cu")
		(net "M_A_CPU0_SA_DQ<22>")
	)
	(segment
		(start 326.12838 -281.503374)
		(end 326.12838 -287.818576)
		(width 0.1016)
		(layer "F.Cu")
		(net "M_A_CPU0_SA_DQ<22>")
	)
	(segment
		(start 310.630062 -290.945062)
		(end 310.891682 -290.945062)
		(width 0.20066)
		(layer "F.Cu")
		(net "M_A_CPU0_SA_DQ<22>")
	)
	(segment
		(start 326.12838 -287.818576)
		(end 325.940928 -288.006028)
		(width 0.1016)
		(layer "F.Cu")
		(net "M_A_CPU0_SA_DQ<22>")
	)
	(segment
		(start 313.980322 -290.915852)
		(end 313.881262 -290.816792)
		(width 0.20066)
		(layer "F.Cu")
		(net "M_A_CPU0_SA_DQ<22>")
	)
	(segment
		(start 321.429888 -290.86556)
		(end 321.229228 -290.6649)
		(width 0.20066)
		(layer "F.Cu")
		(net "M_A_CPU0_SA_DQ<22>")
	)
	(segment
		(start 332.982316 -271.083024)
		(end 332.821026 -271.083024)
		(width 0.088646)
		(layer "F.Cu")
		(net "M_A_CPU0_SA_DQ<22>")
	)
	(segment
		(start 320.208148 -291.55517)
		(end 320.007488 -291.35451)
		(width 0.20066)
		(layer "F.Cu")
		(net "M_A_CPU0_SA_DQ<22>")
	)
	(segment
		(start 320.007488 -291.35451)
		(end 320.007488 -290.86556)
		(width 0.20066)
		(layer "F.Cu")
		(net "M_A_CPU0_SA_DQ<22>")
	)
	(segment
		(start 313.881262 -290.816792)
		(end 312.987182 -290.816792)
		(width 0.20066)
		(layer "F.Cu")
		(net "M_A_CPU0_SA_DQ<22>")
	)
	(segment
		(start 332.821026 -271.083024)
		(end 332.294484 -271.609566)
		(width 0.088646)
		(layer "F.Cu")
		(net "M_A_CPU0_SA_DQ<22>")
	)
	(segment
		(start 333.523844 -270.942308)
		(end 333.523844 -270.651732)
		(width 0.088646)
		(layer "F.Cu")
		(net "M_A_CPU0_SA_DQ<22>")
	)
	(segment
		(start 334.945482 -270.854424)
		(end 334.945482 -271.016984)
		(width 0.088646)
		(layer "F.Cu")
		(net "M_A_CPU0_SA_DQ<22>")
	)
	(segment
		(start 307.853842 -290.391596)
		(end 310.076342 -290.391596)
		(width 0.1016)
		(layer "F.Cu")
		(net "M_A_CPU0_SA_DQ<22>")
	)
	(segment
		(start 322.141088 -290.86556)
		(end 322.141088 -291.35451)
		(width 0.20066)
		(layer "F.Cu")
		(net "M_A_CPU0_SA_DQ<22>")
	)
	(segment
		(start 314.961524 -290.6649)
		(end 314.710572 -290.915852)
		(width 0.20066)
		(layer "F.Cu")
		(net "M_A_CPU0_SA_DQ<22>")
	)
	(segment
		(start 325.940928 -288.006028)
		(end 325.940928 -288.166048)
		(width 0.1016)
		(layer "F.Cu")
		(net "M_A_CPU0_SA_DQ<22>")
	)
	(segment
		(start 319.296288 -290.86556)
		(end 319.296288 -291.35451)
		(width 0.20066)
		(layer "F.Cu")
		(net "M_A_CPU0_SA_DQ<22>")
	)
	(segment
		(start 335.064608 -270.735298)
		(end 334.945482 -270.854424)
		(width 0.088646)
		(layer "F.Cu")
		(net "M_A_CPU0_SA_DQ<22>")
	)
	(segment
		(start 333.424022 -270.55191)
		(end 333.277972 -270.55191)
		(width 0.088646)
		(layer "F.Cu")
		(net "M_A_CPU0_SA_DQ<22>")
	)
	(segment
		(start 305.443382 -290.816792)
		(end 306.940458 -290.816792)
		(width 0.20066)
		(layer "F.Cu")
		(net "M_A_CPU0_SA_DQ<22>")
	)
	(segment
		(start 318.785748 -291.55517)
		(end 318.585088 -291.35451)
		(width 0.20066)
		(layer "F.Cu")
		(net "M_A_CPU0_SA_DQ<22>")
	)
	(segment
		(start 333.99984 -271.074134)
		(end 333.920846 -271.153128)
		(width 0.088646)
		(layer "F.Cu")
		(net "M_A_CPU0_SA_DQ<22>")
	)
	(segment
		(start 310.088026 -290.391596)
		(end 310.316118 -290.391596)
		(width 0.20066)
		(layer "F.Cu")
		(net "M_A_CPU0_SA_DQ<22>")
	)
	(segment
		(start 307.04282 -290.71443)
		(end 307.04282 -290.506912)
		(width 0.20066)
		(layer "F.Cu")
		(net "M_A_CPU0_SA_DQ<22>")
	)
	(segment
		(start 321.940428 -291.55517)
		(end 321.630548 -291.55517)
		(width 0.20066)
		(layer "F.Cu")
		(net "M_A_CPU0_SA_DQ<22>")
	)
	(segment
		(start 325.940928 -288.166048)
		(end 325.940928 -288.601658)
		(width 0.20066)
		(layer "F.Cu")
		(net "M_A_CPU0_SA_DQ<22>")
	)
	(segment
		(start 319.095628 -291.55517)
		(end 318.785748 -291.55517)
		(width 0.20066)
		(layer "F.Cu")
		(net "M_A_CPU0_SA_DQ<22>")
	)
	(segment
		(start 334.539082 -270.98371)
		(end 334.539082 -270.76527)
		(width 0.088646)
		(layer "F.Cu")
		(net "M_A_CPU0_SA_DQ<22>")
	)
	(segment
		(start 334.440784 -270.666972)
		(end 334.23098 -270.666972)
		(width 0.088646)
		(layer "F.Cu")
		(net "M_A_CPU0_SA_DQ<22>")
	)
	(segment
		(start 320.007488 -290.86556)
		(end 319.806828 -290.6649)
		(width 0.20066)
		(layer "F.Cu")
		(net "M_A_CPU0_SA_DQ<22>")
	)
	(segment
		(start 334.839056 -271.12341)
		(end 334.678782 -271.12341)
		(width 0.088646)
		(layer "F.Cu")
		(net "M_A_CPU0_SA_DQ<22>")
	)
	(segment
		(start 325.940928 -288.601658)
		(end 323.877686 -290.6649)
		(width 0.20066)
		(layer "F.Cu")
		(net "M_A_CPU0_SA_DQ<22>")
	)
	(segment
		(start 321.229228 -290.6649)
		(end 320.919348 -290.6649)
		(width 0.20066)
		(layer "F.Cu")
		(net "M_A_CPU0_SA_DQ<22>")
	)
	(segment
		(start 320.518028 -291.55517)
		(end 320.208148 -291.55517)
		(width 0.20066)
		(layer "F.Cu")
		(net "M_A_CPU0_SA_DQ<22>")
	)
	(segment
		(start 333.079598 -270.985742)
		(end 332.982316 -271.083024)
		(width 0.088646)
		(layer "F.Cu")
		(net "M_A_CPU0_SA_DQ<22>")
	)
	(segment
		(start 318.585088 -291.35451)
		(end 318.585088 -290.86556)
		(width 0.20066)
		(layer "F.Cu")
		(net "M_A_CPU0_SA_DQ<22>")
	)
	(segment
		(start 321.630548 -291.55517)
		(end 321.429888 -291.35451)
		(width 0.20066)
		(layer "F.Cu")
		(net "M_A_CPU0_SA_DQ<22>")
	)
	(segment
		(start 320.718688 -290.86556)
		(end 320.718688 -291.35451)
		(width 0.20066)
		(layer "F.Cu")
		(net "M_A_CPU0_SA_DQ<22>")
	)
	(segment
		(start 333.734664 -271.153128)
		(end 333.523844 -270.942308)
		(width 0.088646)
		(layer "F.Cu")
		(net "M_A_CPU0_SA_DQ<22>")
	)
	(segment
		(start 319.296288 -291.35451)
		(end 319.095628 -291.55517)
		(width 0.20066)
		(layer "F.Cu")
		(net "M_A_CPU0_SA_DQ<22>")
	)
	(segment
		(start 310.891682 -290.945062)
		(end 311.020206 -290.816538)
		(width 0.20066)
		(layer "F.Cu")
		(net "M_A_CPU0_SA_DQ<22>")
	)
	(segment
		(start 334.23098 -270.666972)
		(end 334.1751 -270.722852)
		(width 0.088646)
		(layer "F.Cu")
		(net "M_A_CPU0_SA_DQ<22>")
	)
	(segment
		(start 334.539082 -270.76527)
		(end 334.440784 -270.666972)
		(width 0.088646)
		(layer "F.Cu")
		(net "M_A_CPU0_SA_DQ<22>")
	)
	(segment
		(start 326.878188 -277.750016)
		(end 326.12838 -281.503374)
		(width 0.1016)
		(layer "F.Cu")
		(net "M_A_CPU0_SA_DQ<22>")
	)
	(segment
		(start 307.04282 -290.506912)
		(end 307.17871 -290.371022)
		(width 0.20066)
		(layer "F.Cu")
		(net "M_A_CPU0_SA_DQ<22>")
	)
	(segment
		(start 322.341748 -290.6649)
		(end 322.141088 -290.86556)
		(width 0.20066)
		(layer "F.Cu")
		(net "M_A_CPU0_SA_DQ<22>")
	)
	(segment
		(start 321.429888 -291.35451)
		(end 321.429888 -290.86556)
		(width 0.20066)
		(layer "F.Cu")
		(net "M_A_CPU0_SA_DQ<22>")
	)
	(segment
		(start 318.384428 -290.6649)
		(end 314.961524 -290.6649)
		(width 0.20066)
		(layer "F.Cu")
		(net "M_A_CPU0_SA_DQ<22>")
	)
	(segment
		(start 334.945482 -271.016984)
		(end 334.839056 -271.12341)
		(width 0.088646)
		(layer "F.Cu")
		(net "M_A_CPU0_SA_DQ<22>")
	)
	(segment
		(start 322.141088 -291.35451)
		(end 321.940428 -291.55517)
		(width 0.20066)
		(layer "F.Cu")
		(net "M_A_CPU0_SA_DQ<22>")
	)
	(segment
		(start 334.1751 -270.722852)
		(end 333.99984 -271.074134)
		(width 0.088646)
		(layer "F.Cu")
		(net "M_A_CPU0_SA_DQ<22>")
	)
	(segment
		(start 333.523844 -270.651732)
		(end 333.424022 -270.55191)
		(width 0.088646)
		(layer "F.Cu")
		(net "M_A_CPU0_SA_DQ<22>")
	)
	(segment
		(start 332.062328 -271.841722)
		(end 327.712324 -276.19071)
		(width 0.1016)
		(layer "F.Cu")
		(net "M_A_CPU0_SA_DQ<22>")
	)
	(segment
		(start 335.255362 -270.809466)
		(end 335.181194 -270.735298)
		(width 0.088646)
		(layer "F.Cu")
		(net "M_A_CPU0_SA_DQ<22>")
	)
	(segment
		(start 307.833268 -290.371022)
		(end 307.853842 -290.391596)
		(width 0.101854)
		(layer "F.Cu")
		(net "M_A_CPU0_SA_DQ<22>")
	)
	(segment
		(start 320.718688 -291.35451)
		(end 320.518028 -291.55517)
		(width 0.20066)
		(layer "F.Cu")
		(net "M_A_CPU0_SA_DQ<22>")
	)
	(segment
		(start 333.079598 -270.750284)
		(end 333.079598 -270.985742)
		(width 0.088646)
		(layer "F.Cu")
		(net "M_A_CPU0_SA_DQ<22>")
	)
	(segment
		(start 310.316118 -290.391596)
		(end 310.457088 -290.532566)
		(width 0.20066)
		(layer "F.Cu")
		(net "M_A_CPU0_SA_DQ<22>")
	)
	(segment
		(start 310.457088 -290.772088)
		(end 310.630062 -290.945062)
		(width 0.20066)
		(layer "F.Cu")
		(net "M_A_CPU0_SA_DQ<22>")
	)
	(segment
		(start 319.496948 -290.6649)
		(end 319.296288 -290.86556)
		(width 0.20066)
		(layer "F.Cu")
		(net "M_A_CPU0_SA_DQ<22>")
	)
	(segment
		(start 318.585088 -290.86556)
		(end 318.384428 -290.6649)
		(width 0.20066)
		(layer "F.Cu")
		(net "M_A_CPU0_SA_DQ<22>")
	)
	(segment
		(start 334.678782 -271.12341)
		(end 334.539082 -270.98371)
		(width 0.088646)
		(layer "F.Cu")
		(net "M_A_CPU0_SA_DQ<22>")
	)
	(segment
		(start 307.76291 -290.371022)
		(end 307.833268 -290.371022)
		(width 0.101854)
		(layer "F.Cu")
		(net "M_A_CPU0_SA_DQ<22>")
	)
	(segment
		(start 311.02046 -290.816792)
		(end 312.987182 -290.816792)
		(width 0.20066)
		(layer "F.Cu")
		(net "M_A_CPU0_SA_DQ<22>")
	)
	(segment
		(start 323.877686 -290.6649)
		(end 322.341748 -290.6649)
		(width 0.20066)
		(layer "F.Cu")
		(net "M_A_CPU0_SA_DQ<22>")
	)
	(segment
		(start 310.076342 -290.391596)
		(end 310.088026 -290.391596)
		(width 0.101854)
		(layer "F.Cu")
		(net "M_A_CPU0_SA_DQ<22>")
	)
	(segment
		(start 320.919348 -290.6649)
		(end 320.718688 -290.86556)
		(width 0.20066)
		(layer "F.Cu")
		(net "M_A_CPU0_SA_DQ<22>")
	)
	(segment
		(start 311.020206 -290.816538)
		(end 311.02046 -290.816792)
		(width 0.20066)
		(layer "F.Cu")
		(net "M_A_CPU0_SA_DQ<22>")
	)
	(segment
		(start 306.940458 -290.816792)
		(end 307.04282 -290.71443)
		(width 0.20066)
		(layer "F.Cu")
		(net "M_A_CPU0_SA_DQ<22>")
	)
	(segment
		(start 333.277972 -270.55191)
		(end 333.079598 -270.750284)
		(width 0.088646)
		(layer "F.Cu")
		(net "M_A_CPU0_SA_DQ<22>")
	)
	(segment
		(start 310.457088 -290.532566)
		(end 310.457088 -290.772088)
		(width 0.20066)
		(layer "F.Cu")
		(net "M_A_CPU0_SA_DQ<22>")
	)
	(segment
		(start 327.712324 -276.19071)
		(end 326.878188 -277.750016)
		(width 0.1016)
		(layer "F.Cu")
		(net "M_A_CPU0_SA_DQ<22>")
	)
	(segment
		(start 333.845662 -270.475456)
		(end 333.58328 -270.213074)
		(width 0.088646)
		(layer "F.Cu")
		(net "M_A_CPU0_SA_DQ<21>")
	)
	(segment
		(start 316.060328 -289.824414)
		(end 315.859668 -290.025074)
		(width 0.20066)
		(layer "F.Cu")
		(net "M_A_CPU0_SA_DQ<21>")
	)
	(segment
		(start 310.580278 -289.966654)
		(end 308.887114 -289.966654)
		(width 0.20066)
		(layer "F.Cu")
		(net "M_A_CPU0_SA_DQ<21>")
	)
	(segment
		(start 317.993268 -289.484816)
		(end 317.683388 -289.484816)
		(width 0.20066)
		(layer "F.Cu")
		(net "M_A_CPU0_SA_DQ<21>")
	)
	(segment
		(start 332.794102 -270.678656)
		(end 332.574138 -270.89862)
		(width 0.088646)
		(layer "F.Cu")
		(net "M_A_CPU0_SA_DQ<21>")
	)
	(segment
		(start 312.086752 -290.405058)
		(end 311.91708 -290.405058)
		(width 0.101854)
		(layer "F.Cu")
		(net "M_A_CPU0_SA_DQ<21>")
	)
	(segment
		(start 332.573884 -270.89862)
		(end 332.20279 -271.269714)
		(width 0.1016)
		(layer "F.Cu")
		(net "M_A_CPU0_SA_DQ<21>")
	)
	(segment
		(start 311.91708 -290.405058)
		(end 311.529984 -290.405058)
		(width 0.20066)
		(layer "F.Cu")
		(net "M_A_CPU0_SA_DQ<21>")
	)
	(segment
		(start 301.967138 -289.966654)
		(end 301.967392 -289.9664)
		(width 0.20066)
		(layer "F.Cu")
		(net "M_A_CPU0_SA_DQ<21>")
	)
	(segment
		(start 318.905128 -289.685476)
		(end 318.905128 -289.824414)
		(width 0.20066)
		(layer "F.Cu")
		(net "M_A_CPU0_SA_DQ<21>")
	)
	(segment
		(start 311.430924 -289.862768)
		(end 311.232042 -289.663886)
		(width 0.20066)
		(layer "F.Cu")
		(net "M_A_CPU0_SA_DQ<21>")
	)
	(segment
		(start 307.21427 -289.966654)
		(end 308.887114 -289.966654)
		(width 0.20066)
		(layer "F.Cu")
		(net "M_A_CPU0_SA_DQ<21>")
	)
	(segment
		(start 310.883046 -289.663886)
		(end 310.580278 -289.966654)
		(width 0.20066)
		(layer "F.Cu")
		(net "M_A_CPU0_SA_DQ<21>")
	)
	(segment
		(start 302.603408 -290.218368)
		(end 302.837596 -289.98418)
		(width 0.20066)
		(layer "F.Cu")
		(net "M_A_CPU0_SA_DQ<21>")
	)
	(segment
		(start 319.616328 -289.685476)
		(end 319.415668 -289.484816)
		(width 0.20066)
		(layer "F.Cu")
		(net "M_A_CPU0_SA_DQ<21>")
	)
	(segment
		(start 313.843416 -290.391596)
		(end 312.12536 -290.391596)
		(width 0.1016)
		(layer "F.Cu")
		(net "M_A_CPU0_SA_DQ<21>")
	)
	(segment
		(start 325.702168 -286.845502)
		(end 325.692008 -286.855662)
		(width 0.101854)
		(layer "F.Cu")
		(net "M_A_CPU0_SA_DQ<21>")
	)
	(segment
		(start 302.837596 -289.98418)
		(end 302.837596 -289.696144)
		(width 0.20066)
		(layer "F.Cu")
		(net "M_A_CPU0_SA_DQ<21>")
	)
	(segment
		(start 306.789328 -289.541712)
		(end 307.21427 -289.966654)
		(width 0.20066)
		(layer "F.Cu")
		(net "M_A_CPU0_SA_DQ<21>")
	)
	(segment
		(start 323.96938 -289.04692)
		(end 324.113652 -289.191192)
		(width 0.20066)
		(layer "F.Cu")
		(net "M_A_CPU0_SA_DQ<21>")
	)
	(segment
		(start 301.343314 -289.966654)
		(end 301.967138 -289.966654)
		(width 0.20066)
		(layer "F.Cu")
		(net "M_A_CPU0_SA_DQ<21>")
	)
	(segment
		(start 312.12536 -290.391596)
		(end 312.086752 -290.405058)
		(width 0.1016)
		(layer "F.Cu")
		(net "M_A_CPU0_SA_DQ<21>")
	)
	(segment
		(start 311.232042 -289.663886)
		(end 310.883046 -289.663886)
		(width 0.20066)
		(layer "F.Cu")
		(net "M_A_CPU0_SA_DQ<21>")
	)
	(segment
		(start 314.12688 -290.39693)
		(end 313.856116 -290.39693)
		(width 0.101854)
		(layer "F.Cu")
		(net "M_A_CPU0_SA_DQ<21>")
	)
	(segment
		(start 324.900544 -288.688272)
		(end 324.616572 -288.688272)
		(width 0.20066)
		(layer "F.Cu")
		(net "M_A_CPU0_SA_DQ<21>")
	)
	(segment
		(start 333.58328 -270.213074)
		(end 333.32547 -270.213074)
		(width 0.088646)
		(layer "F.Cu")
		(net "M_A_CPU0_SA_DQ<21>")
	)
	(segment
		(start 311.529984 -290.405058)
		(end 311.430924 -290.305998)
		(width 0.20066)
		(layer "F.Cu")
		(net "M_A_CPU0_SA_DQ<21>")
	)
	(segment
		(start 302.837596 -289.696144)
		(end 303.0093 -289.52444)
		(width 0.20066)
		(layer "F.Cu")
		(net "M_A_CPU0_SA_DQ<21>")
	)
	(segment
		(start 316.771528 -289.824414)
		(end 316.771528 -289.685476)
		(width 0.20066)
		(layer "F.Cu")
		(net "M_A_CPU0_SA_DQ<21>")
	)
	(segment
		(start 317.482728 -289.685476)
		(end 317.482728 -289.824414)
		(width 0.20066)
		(layer "F.Cu")
		(net "M_A_CPU0_SA_DQ<21>")
	)
	(segment
		(start 333.32547 -270.213074)
		(end 332.859888 -270.678656)
		(width 0.088646)
		(layer "F.Cu")
		(net "M_A_CPU0_SA_DQ<21>")
	)
	(segment
		(start 314.27166 -290.39693)
		(end 314.12688 -290.39693)
		(width 0.20066)
		(layer "F.Cu")
		(net "M_A_CPU0_SA_DQ<21>")
	)
	(segment
		(start 304.319178 -289.52444)
		(end 304.370994 -289.52444)
		(width 0.101854)
		(layer "F.Cu")
		(net "M_A_CPU0_SA_DQ<21>")
	)
	(segment
		(start 323.894704 -289.694112)
		(end 323.610732 -289.694112)
		(width 0.20066)
		(layer "F.Cu")
		(net "M_A_CPU0_SA_DQ<21>")
	)
	(segment
		(start 325.119492 -288.185352)
		(end 325.119492 -288.469324)
		(width 0.20066)
		(layer "F.Cu")
		(net "M_A_CPU0_SA_DQ<21>")
	)
	(segment
		(start 315.859668 -290.025074)
		(end 314.643516 -290.025074)
		(width 0.20066)
		(layer "F.Cu")
		(net "M_A_CPU0_SA_DQ<21>")
	)
	(segment
		(start 319.105788 -289.484816)
		(end 318.905128 -289.685476)
		(width 0.20066)
		(layer "F.Cu")
		(net "M_A_CPU0_SA_DQ<21>")
	)
	(segment
		(start 316.060328 -289.685476)
		(end 316.060328 -289.824414)
		(width 0.20066)
		(layer "F.Cu")
		(net "M_A_CPU0_SA_DQ<21>")
	)
	(segment
		(start 313.856116 -290.39693)
		(end 313.843416 -290.391596)
		(width 0.1016)
		(layer "F.Cu")
		(net "M_A_CPU0_SA_DQ<21>")
	)
	(segment
		(start 316.570868 -289.484816)
		(end 316.260988 -289.484816)
		(width 0.20066)
		(layer "F.Cu")
		(net "M_A_CPU0_SA_DQ<21>")
	)
	(segment
		(start 323.610732 -289.694112)
		(end 323.46646 -289.54984)
		(width 0.20066)
		(layer "F.Cu")
		(net "M_A_CPU0_SA_DQ<21>")
	)
	(segment
		(start 324.113652 -289.191192)
		(end 324.113652 -289.475164)
		(width 0.20066)
		(layer "F.Cu")
		(net "M_A_CPU0_SA_DQ<21>")
	)
	(segment
		(start 325.43115 -287.301178)
		(end 324.97522 -287.757108)
		(width 0.20066)
		(layer "F.Cu")
		(net "M_A_CPU0_SA_DQ<21>")
	)
	(segment
		(start 325.702168 -286.807402)
		(end 325.702168 -286.845502)
		(width 0.101854)
		(layer "F.Cu")
		(net "M_A_CPU0_SA_DQ<21>")
	)
	(segment
		(start 304.388266 -289.541712)
		(end 306.60848 -289.541712)
		(width 0.1016)
		(layer "F.Cu")
		(net "M_A_CPU0_SA_DQ<21>")
	)
	(segment
		(start 325.82358 -281.472386)
		(end 325.82358 -286.68599)
		(width 0.1016)
		(layer "F.Cu")
		(net "M_A_CPU0_SA_DQ<21>")
	)
	(segment
		(start 323.96938 -288.762948)
		(end 323.96938 -289.04692)
		(width 0.20066)
		(layer "F.Cu")
		(net "M_A_CPU0_SA_DQ<21>")
	)
	(segment
		(start 318.905128 -289.824414)
		(end 318.704468 -290.025074)
		(width 0.20066)
		(layer "F.Cu")
		(net "M_A_CPU0_SA_DQ<21>")
	)
	(segment
		(start 318.394588 -290.025074)
		(end 318.193928 -289.824414)
		(width 0.20066)
		(layer "F.Cu")
		(net "M_A_CPU0_SA_DQ<21>")
	)
	(segment
		(start 327.465182 -276.006306)
		(end 326.587358 -277.646638)
		(width 0.1016)
		(layer "F.Cu")
		(net "M_A_CPU0_SA_DQ<21>")
	)
	(segment
		(start 304.370994 -289.52444)
		(end 304.388266 -289.541712)
		(width 0.101854)
		(layer "F.Cu")
		(net "M_A_CPU0_SA_DQ<21>")
	)
	(segment
		(start 318.704468 -290.025074)
		(end 318.394588 -290.025074)
		(width 0.20066)
		(layer "F.Cu")
		(net "M_A_CPU0_SA_DQ<21>")
	)
	(segment
		(start 332.859888 -270.678656)
		(end 332.794102 -270.678656)
		(width 0.088646)
		(layer "F.Cu")
		(net "M_A_CPU0_SA_DQ<21>")
	)
	(segment
		(start 317.482728 -289.824414)
		(end 317.282068 -290.025074)
		(width 0.20066)
		(layer "F.Cu")
		(net "M_A_CPU0_SA_DQ<21>")
	)
	(segment
		(start 306.644294 -289.541712)
		(end 306.789328 -289.541712)
		(width 0.20066)
		(layer "F.Cu")
		(net "M_A_CPU0_SA_DQ<21>")
	)
	(segment
		(start 318.193928 -289.685476)
		(end 317.993268 -289.484816)
		(width 0.20066)
		(layer "F.Cu")
		(net "M_A_CPU0_SA_DQ<21>")
	)
	(segment
		(start 325.670926 -286.855662)
		(end 325.670164 -286.855662)
		(width 0.20066)
		(layer "F.Cu")
		(net "M_A_CPU0_SA_DQ<21>")
	)
	(segment
		(start 324.113652 -289.475164)
		(end 323.894704 -289.694112)
		(width 0.20066)
		(layer "F.Cu")
		(net "M_A_CPU0_SA_DQ<21>")
	)
	(segment
		(start 319.616328 -289.824414)
		(end 319.616328 -289.685476)
		(width 0.20066)
		(layer "F.Cu")
		(net "M_A_CPU0_SA_DQ<21>")
	)
	(segment
		(start 324.97522 -287.757108)
		(end 324.97522 -288.04108)
		(width 0.20066)
		(layer "F.Cu")
		(net "M_A_CPU0_SA_DQ<21>")
	)
	(segment
		(start 318.193928 -289.824414)
		(end 318.193928 -289.685476)
		(width 0.20066)
		(layer "F.Cu")
		(net "M_A_CPU0_SA_DQ<21>")
	)
	(segment
		(start 325.692008 -286.855662)
		(end 325.670926 -286.855662)
		(width 0.101854)
		(layer "F.Cu")
		(net "M_A_CPU0_SA_DQ<21>")
	)
	(segment
		(start 324.616572 -288.688272)
		(end 324.4723 -288.544)
		(width 0.20066)
		(layer "F.Cu")
		(net "M_A_CPU0_SA_DQ<21>")
	)
	(segment
		(start 325.82358 -286.68599)
		(end 325.702168 -286.807402)
		(width 0.1016)
		(layer "F.Cu")
		(net "M_A_CPU0_SA_DQ<21>")
	)
	(segment
		(start 324.97522 -288.04108)
		(end 325.119492 -288.185352)
		(width 0.20066)
		(layer "F.Cu")
		(net "M_A_CPU0_SA_DQ<21>")
	)
	(segment
		(start 325.43115 -287.094676)
		(end 325.43115 -287.301178)
		(width 0.20066)
		(layer "F.Cu")
		(net "M_A_CPU0_SA_DQ<21>")
	)
	(segment
		(start 311.430924 -290.305998)
		(end 311.430924 -289.862768)
		(width 0.20066)
		(layer "F.Cu")
		(net "M_A_CPU0_SA_DQ<21>")
	)
	(segment
		(start 316.972188 -290.025074)
		(end 316.771528 -289.824414)
		(width 0.20066)
		(layer "F.Cu")
		(net "M_A_CPU0_SA_DQ<21>")
	)
	(segment
		(start 325.670164 -286.855662)
		(end 325.43115 -287.094676)
		(width 0.20066)
		(layer "F.Cu")
		(net "M_A_CPU0_SA_DQ<21>")
	)
	(segment
		(start 323.46646 -289.54984)
		(end 323.182488 -289.54984)
		(width 0.20066)
		(layer "F.Cu")
		(net "M_A_CPU0_SA_DQ<21>")
	)
	(segment
		(start 316.771528 -289.685476)
		(end 316.570868 -289.484816)
		(width 0.20066)
		(layer "F.Cu")
		(net "M_A_CPU0_SA_DQ<21>")
	)
	(segment
		(start 306.60848 -289.541712)
		(end 306.644294 -289.541712)
		(width 0.101854)
		(layer "F.Cu")
		(net "M_A_CPU0_SA_DQ<21>")
	)
	(segment
		(start 317.683388 -289.484816)
		(end 317.482728 -289.685476)
		(width 0.20066)
		(layer "F.Cu")
		(net "M_A_CPU0_SA_DQ<21>")
	)
	(segment
		(start 317.282068 -290.025074)
		(end 316.972188 -290.025074)
		(width 0.20066)
		(layer "F.Cu")
		(net "M_A_CPU0_SA_DQ<21>")
	)
	(segment
		(start 323.182488 -289.54984)
		(end 322.707254 -290.025074)
		(width 0.20066)
		(layer "F.Cu")
		(net "M_A_CPU0_SA_DQ<21>")
	)
	(segment
		(start 326.587358 -277.646638)
		(end 325.82358 -281.472386)
		(width 0.1016)
		(layer "F.Cu")
		(net "M_A_CPU0_SA_DQ<21>")
	)
	(segment
		(start 302.21936 -290.218368)
		(end 302.603408 -290.218368)
		(width 0.20066)
		(layer "F.Cu")
		(net "M_A_CPU0_SA_DQ<21>")
	)
	(segment
		(start 322.707254 -290.025074)
		(end 319.816988 -290.025074)
		(width 0.20066)
		(layer "F.Cu")
		(net "M_A_CPU0_SA_DQ<21>")
	)
	(segment
		(start 324.188328 -288.544)
		(end 323.96938 -288.762948)
		(width 0.20066)
		(layer "F.Cu")
		(net "M_A_CPU0_SA_DQ<21>")
	)
	(segment
		(start 324.4723 -288.544)
		(end 324.188328 -288.544)
		(width 0.20066)
		(layer "F.Cu")
		(net "M_A_CPU0_SA_DQ<21>")
	)
	(segment
		(start 301.967392 -289.9664)
		(end 302.21936 -290.218368)
		(width 0.20066)
		(layer "F.Cu")
		(net "M_A_CPU0_SA_DQ<21>")
	)
	(segment
		(start 332.20279 -271.269714)
		(end 327.465182 -276.006306)
		(width 0.1016)
		(layer "F.Cu")
		(net "M_A_CPU0_SA_DQ<21>")
	)
	(segment
		(start 332.574138 -270.89862)
		(end 332.573884 -270.89862)
		(width 0.088646)
		(layer "F.Cu")
		(net "M_A_CPU0_SA_DQ<21>")
	)
	(segment
		(start 325.119492 -288.469324)
		(end 324.900544 -288.688272)
		(width 0.20066)
		(layer "F.Cu")
		(net "M_A_CPU0_SA_DQ<21>")
	)
	(segment
		(start 316.260988 -289.484816)
		(end 316.060328 -289.685476)
		(width 0.20066)
		(layer "F.Cu")
		(net "M_A_CPU0_SA_DQ<21>")
	)
	(segment
		(start 303.0093 -289.52444)
		(end 304.319178 -289.52444)
		(width 0.20066)
		(layer "F.Cu")
		(net "M_A_CPU0_SA_DQ<21>")
	)
	(segment
		(start 319.816988 -290.025074)
		(end 319.616328 -289.824414)
		(width 0.20066)
		(layer "F.Cu")
		(net "M_A_CPU0_SA_DQ<21>")
	)
	(segment
		(start 314.643516 -290.025074)
		(end 314.27166 -290.39693)
		(width 0.20066)
		(layer "F.Cu")
		(net "M_A_CPU0_SA_DQ<21>")
	)
	(segment
		(start 319.415668 -289.484816)
		(end 319.105788 -289.484816)
		(width 0.20066)
		(layer "F.Cu")
		(net "M_A_CPU0_SA_DQ<21>")
	)
	(segment
		(start 316.045088 -292.045136)
		(end 316.245748 -292.245796)
		(width 0.20066)
		(layer "F.Cu")
		(net "M_A_CPU0_SA_DQ<20>")
	)
	(segment
		(start 317.266828 -291.349176)
		(end 317.467488 -291.549836)
		(width 0.20066)
		(layer "F.Cu")
		(net "M_A_CPU0_SA_DQ<20>")
	)
	(segment
		(start 303.727866 -291.216334)
		(end 304.319178 -291.216334)
		(width 0.20066)
		(layer "F.Cu")
		(net "M_A_CPU0_SA_DQ<20>")
	)
	(segment
		(start 303.54778 -291.684456)
		(end 303.54778 -291.39642)
		(width 0.20066)
		(layer "F.Cu")
		(net "M_A_CPU0_SA_DQ<20>")
	)
	(segment
		(start 317.668148 -292.245796)
		(end 322.556124 -292.245796)
		(width 0.20066)
		(layer "F.Cu")
		(net "M_A_CPU0_SA_DQ<20>")
	)
	(segment
		(start 331.262228 -273.074384)
		(end 332.700884 -271.635728)
		(width 0.088646)
		(layer "F.Cu")
		(net "M_A_CPU0_SA_DQ<20>")
	)
	(segment
		(start 332.700884 -271.635728)
		(end 332.874874 -271.635728)
		(width 0.088646)
		(layer "F.Cu")
		(net "M_A_CPU0_SA_DQ<20>")
	)
	(segment
		(start 314.468002 -292.245796)
		(end 315.133228 -292.245796)
		(width 0.20066)
		(layer "F.Cu")
		(net "M_A_CPU0_SA_DQ<20>")
	)
	(segment
		(start 323.801486 -291.729922)
		(end 326.331326 -289.200082)
		(width 0.20066)
		(layer "F.Cu")
		(net "M_A_CPU0_SA_DQ<20>")
	)
	(segment
		(start 310.45277 -291.666676)
		(end 311.560464 -292.125908)
		(width 0.20066)
		(layer "F.Cu")
		(net "M_A_CPU0_SA_DQ<20>")
	)
	(segment
		(start 316.555628 -292.245796)
		(end 316.756288 -292.045136)
		(width 0.20066)
		(layer "F.Cu")
		(net "M_A_CPU0_SA_DQ<20>")
	)
	(segment
		(start 317.467488 -291.549836)
		(end 317.467488 -292.045136)
		(width 0.20066)
		(layer "F.Cu")
		(net "M_A_CPU0_SA_DQ<20>")
	)
	(segment
		(start 315.333888 -292.045136)
		(end 315.333888 -291.549836)
		(width 0.20066)
		(layer "F.Cu")
		(net "M_A_CPU0_SA_DQ<20>")
	)
	(segment
		(start 313.94908 -292.102794)
		(end 314.325 -292.102794)
		(width 0.20066)
		(layer "F.Cu")
		(net "M_A_CPU0_SA_DQ<20>")
	)
	(segment
		(start 332.95463 -271.380458)
		(end 333.045816 -271.289272)
		(width 0.088646)
		(layer "F.Cu")
		(net "M_A_CPU0_SA_DQ<20>")
	)
	(segment
		(start 322.556124 -292.245796)
		(end 323.801486 -291.729922)
		(width 0.20066)
		(layer "F.Cu")
		(net "M_A_CPU0_SA_DQ<20>")
	)
	(segment
		(start 316.756288 -291.549836)
		(end 316.956948 -291.349176)
		(width 0.20066)
		(layer "F.Cu")
		(net "M_A_CPU0_SA_DQ<20>")
	)
	(segment
		(start 333.045816 -271.289272)
		(end 333.375762 -271.289272)
		(width 0.088646)
		(layer "F.Cu")
		(net "M_A_CPU0_SA_DQ<20>")
	)
	(segment
		(start 311.93867 -292.125908)
		(end 311.97296 -292.091618)
		(width 0.101854)
		(layer "F.Cu")
		(net "M_A_CPU0_SA_DQ<20>")
	)
	(segment
		(start 307.295804 -291.519356)
		(end 307.878226 -291.519356)
		(width 0.20066)
		(layer "F.Cu")
		(net "M_A_CPU0_SA_DQ<20>")
	)
	(segment
		(start 316.756288 -292.045136)
		(end 316.756288 -291.549836)
		(width 0.20066)
		(layer "F.Cu")
		(net "M_A_CPU0_SA_DQ<20>")
	)
	(segment
		(start 304.402998 -291.241734)
		(end 306.57419 -291.241734)
		(width 0.1016)
		(layer "F.Cu")
		(net "M_A_CPU0_SA_DQ<20>")
	)
	(segment
		(start 302.677576 -291.666676)
		(end 302.929544 -291.918644)
		(width 0.20066)
		(layer "F.Cu")
		(net "M_A_CPU0_SA_DQ<20>")
	)
	(segment
		(start 303.54778 -291.39642)
		(end 303.727866 -291.216334)
		(width 0.20066)
		(layer "F.Cu")
		(net "M_A_CPU0_SA_DQ<20>")
	)
	(segment
		(start 326.43318 -289.098228)
		(end 326.43318 -281.534108)
		(width 0.1016)
		(layer "F.Cu")
		(net "M_A_CPU0_SA_DQ<20>")
	)
	(segment
		(start 306.57419 -291.241734)
		(end 306.584858 -291.231066)
		(width 0.101854)
		(layer "F.Cu")
		(net "M_A_CPU0_SA_DQ<20>")
	)
	(segment
		(start 315.333888 -291.549836)
		(end 315.534548 -291.349176)
		(width 0.20066)
		(layer "F.Cu")
		(net "M_A_CPU0_SA_DQ<20>")
	)
	(segment
		(start 302.929544 -291.918644)
		(end 303.313592 -291.918644)
		(width 0.20066)
		(layer "F.Cu")
		(net "M_A_CPU0_SA_DQ<20>")
	)
	(segment
		(start 326.331326 -289.200082)
		(end 326.43318 -289.098228)
		(width 0.1016)
		(layer "F.Cu")
		(net "M_A_CPU0_SA_DQ<20>")
	)
	(segment
		(start 316.245748 -292.245796)
		(end 316.555628 -292.245796)
		(width 0.20066)
		(layer "F.Cu")
		(net "M_A_CPU0_SA_DQ<20>")
	)
	(segment
		(start 316.045088 -291.549836)
		(end 316.045088 -292.045136)
		(width 0.20066)
		(layer "F.Cu")
		(net "M_A_CPU0_SA_DQ<20>")
	)
	(segment
		(start 311.89168 -292.125908)
		(end 311.93867 -292.125908)
		(width 0.101854)
		(layer "F.Cu")
		(net "M_A_CPU0_SA_DQ<20>")
	)
	(segment
		(start 306.584858 -291.231066)
		(end 306.644294 -291.231066)
		(width 0.101854)
		(layer "F.Cu")
		(net "M_A_CPU0_SA_DQ<20>")
	)
	(segment
		(start 326.43318 -281.534108)
		(end 327.168256 -277.85441)
		(width 0.1016)
		(layer "F.Cu")
		(net "M_A_CPU0_SA_DQ<20>")
	)
	(segment
		(start 307.878226 -291.519356)
		(end 308.025546 -291.666676)
		(width 0.20066)
		(layer "F.Cu")
		(net "M_A_CPU0_SA_DQ<20>")
	)
	(segment
		(start 314.325 -292.102794)
		(end 314.468002 -292.245796)
		(width 0.20066)
		(layer "F.Cu")
		(net "M_A_CPU0_SA_DQ<20>")
	)
	(segment
		(start 315.133228 -292.245796)
		(end 315.333888 -292.045136)
		(width 0.20066)
		(layer "F.Cu")
		(net "M_A_CPU0_SA_DQ<20>")
	)
	(segment
		(start 308.887114 -291.666676)
		(end 310.45277 -291.666676)
		(width 0.20066)
		(layer "F.Cu")
		(net "M_A_CPU0_SA_DQ<20>")
	)
	(segment
		(start 313.935872 -292.102794)
		(end 313.94908 -292.102794)
		(width 0.101854)
		(layer "F.Cu")
		(net "M_A_CPU0_SA_DQ<20>")
	)
	(segment
		(start 308.025546 -291.666676)
		(end 308.887114 -291.666676)
		(width 0.20066)
		(layer "F.Cu")
		(net "M_A_CPU0_SA_DQ<20>")
	)
	(segment
		(start 327.958704 -276.377146)
		(end 331.240384 -273.09572)
		(width 0.1016)
		(layer "F.Cu")
		(net "M_A_CPU0_SA_DQ<20>")
	)
	(segment
		(start 332.874874 -271.635728)
		(end 332.95463 -271.555972)
		(width 0.088646)
		(layer "F.Cu")
		(net "M_A_CPU0_SA_DQ<20>")
	)
	(segment
		(start 315.844428 -291.349176)
		(end 316.045088 -291.549836)
		(width 0.20066)
		(layer "F.Cu")
		(net "M_A_CPU0_SA_DQ<20>")
	)
	(segment
		(start 301.343314 -291.666676)
		(end 302.677576 -291.666676)
		(width 0.20066)
		(layer "F.Cu")
		(net "M_A_CPU0_SA_DQ<20>")
	)
	(segment
		(start 315.534548 -291.349176)
		(end 315.844428 -291.349176)
		(width 0.20066)
		(layer "F.Cu")
		(net "M_A_CPU0_SA_DQ<20>")
	)
	(segment
		(start 327.168256 -277.85441)
		(end 327.958704 -276.377146)
		(width 0.1016)
		(layer "F.Cu")
		(net "M_A_CPU0_SA_DQ<20>")
	)
	(segment
		(start 304.377598 -291.216334)
		(end 304.402998 -291.241734)
		(width 0.101854)
		(layer "F.Cu")
		(net "M_A_CPU0_SA_DQ<20>")
	)
	(segment
		(start 331.257148 -273.07921)
		(end 331.262228 -273.074384)
		(width 0.088646)
		(layer "F.Cu")
		(net "M_A_CPU0_SA_DQ<20>")
	)
	(segment
		(start 311.560464 -292.125908)
		(end 311.89168 -292.125908)
		(width 0.20066)
		(layer "F.Cu")
		(net "M_A_CPU0_SA_DQ<20>")
	)
	(segment
		(start 304.319178 -291.216334)
		(end 304.377598 -291.216334)
		(width 0.101854)
		(layer "F.Cu")
		(net "M_A_CPU0_SA_DQ<20>")
	)
	(segment
		(start 311.97296 -292.091618)
		(end 313.924696 -292.091618)
		(width 0.1016)
		(layer "F.Cu")
		(net "M_A_CPU0_SA_DQ<20>")
	)
	(segment
		(start 317.467488 -292.045136)
		(end 317.668148 -292.245796)
		(width 0.20066)
		(layer "F.Cu")
		(net "M_A_CPU0_SA_DQ<20>")
	)
	(segment
		(start 306.644294 -291.231066)
		(end 307.007514 -291.231066)
		(width 0.20066)
		(layer "F.Cu")
		(net "M_A_CPU0_SA_DQ<20>")
	)
	(segment
		(start 332.95463 -271.555972)
		(end 332.95463 -271.380458)
		(width 0.088646)
		(layer "F.Cu")
		(net "M_A_CPU0_SA_DQ<20>")
	)
	(segment
		(start 307.007514 -291.231066)
		(end 307.295804 -291.519356)
		(width 0.20066)
		(layer "F.Cu")
		(net "M_A_CPU0_SA_DQ<20>")
	)
	(segment
		(start 331.240384 -273.09572)
		(end 331.257148 -273.07921)
		(width 0.088646)
		(layer "F.Cu")
		(net "M_A_CPU0_SA_DQ<20>")
	)
	(segment
		(start 303.313592 -291.918644)
		(end 303.54778 -291.684456)
		(width 0.20066)
		(layer "F.Cu")
		(net "M_A_CPU0_SA_DQ<20>")
	)
	(segment
		(start 313.924696 -292.091618)
		(end 313.935872 -292.102794)
		(width 0.101854)
		(layer "F.Cu")
		(net "M_A_CPU0_SA_DQ<20>")
	)
	(segment
		(start 316.956948 -291.349176)
		(end 317.266828 -291.349176)
		(width 0.20066)
		(layer "F.Cu")
		(net "M_A_CPU0_SA_DQ<20>")
	)
	(segment
		(start 331.734668 -298.981622)
		(end 331.717142 -299.12437)
		(width 0.1016)
		(layer "F.Cu")
		(net "M_A_CPU0_SA_DQ<1>")
	)
	(segment
		(start 332.927452 -279.84196)
		(end 332.64602 -280.123392)
		(width 0.1016)
		(layer "F.Cu")
		(net "M_A_CPU0_SA_DQ<1>")
	)
	(segment
		(start 332.64602 -280.123392)
		(end 332.616556 -280.270966)
		(width 0.1016)
		(layer "F.Cu")
		(net "M_A_CPU0_SA_DQ<1>")
	)
	(segment
		(start 302.837596 -314.346082)
		(end 303.008538 -314.17514)
		(width 0.20066)
		(layer "F.Cu")
		(net "M_A_CPU0_SA_DQ<1>")
	)
	(segment
		(start 332.670404 -280.687018)
		(end 332.512162 -280.792428)
		(width 0.1016)
		(layer "F.Cu")
		(net "M_A_CPU0_SA_DQ<1>")
	)
	(segment
		(start 314.10148 -315.05271)
		(end 314.062872 -315.05271)
		(width 0.101854)
		(layer "F.Cu")
		(net "M_A_CPU0_SA_DQ<1>")
	)
	(segment
		(start 314.523882 -314.612274)
		(end 314.523882 -314.851288)
		(width 0.20066)
		(layer "F.Cu")
		(net "M_A_CPU0_SA_DQ<1>")
	)
	(segment
		(start 331.594206 -298.529502)
		(end 331.555852 -298.683934)
		(width 0.1016)
		(layer "F.Cu")
		(net "M_A_CPU0_SA_DQ<1>")
	)
	(segment
		(start 311.984136 -315.041534)
		(end 311.973976 -315.051694)
		(width 0.101854)
		(layer "F.Cu")
		(net "M_A_CPU0_SA_DQ<1>")
	)
	(segment
		(start 301.343314 -314.616592)
		(end 301.967138 -314.616592)
		(width 0.20066)
		(layer "F.Cu")
		(net "M_A_CPU0_SA_DQ<1>")
	)
	(segment
		(start 333.231998 -279.571958)
		(end 333.231998 -279.762458)
		(width 0.088646)
		(layer "F.Cu")
		(net "M_A_CPU0_SA_DQ<1>")
	)
	(segment
		(start 302.21936 -314.868306)
		(end 302.603408 -314.868306)
		(width 0.20066)
		(layer "F.Cu")
		(net "M_A_CPU0_SA_DQ<1>")
	)
	(segment
		(start 314.062872 -315.05271)
		(end 314.051696 -315.041534)
		(width 0.101854)
		(layer "F.Cu")
		(net "M_A_CPU0_SA_DQ<1>")
	)
	(segment
		(start 332.095348 -297.551348)
		(end 331.953616 -297.63593)
		(width 0.1016)
		(layer "F.Cu")
		(net "M_A_CPU0_SA_DQ<1>")
	)
	(segment
		(start 332.17358 -297.239182)
		(end 332.095348 -297.551348)
		(width 0.1016)
		(layer "F.Cu")
		(net "M_A_CPU0_SA_DQ<1>")
	)
	(segment
		(start 306.58308 -314.19165)
		(end 306.589176 -314.185554)
		(width 0.101854)
		(layer "F.Cu")
		(net "M_A_CPU0_SA_DQ<1>")
	)
	(segment
		(start 307.381656 -314.616592)
		(end 308.887114 -314.616592)
		(width 0.20066)
		(layer "F.Cu")
		(net "M_A_CPU0_SA_DQ<1>")
	)
	(segment
		(start 331.970888 -298.414186)
		(end 331.846428 -298.488354)
		(width 0.1016)
		(layer "F.Cu")
		(net "M_A_CPU0_SA_DQ<1>")
	)
	(segment
		(start 301.967392 -314.616338)
		(end 302.21936 -314.868306)
		(width 0.20066)
		(layer "F.Cu")
		(net "M_A_CPU0_SA_DQ<1>")
	)
	(segment
		(start 311.351422 -315.051694)
		(end 311.191402 -314.891674)
		(width 0.20066)
		(layer "F.Cu")
		(net "M_A_CPU0_SA_DQ<1>")
	)
	(segment
		(start 331.555852 -298.683934)
		(end 331.734668 -298.981622)
		(width 0.1016)
		(layer "F.Cu")
		(net "M_A_CPU0_SA_DQ<1>")
	)
	(segment
		(start 304.319178 -314.17514)
		(end 304.336704 -314.17514)
		(width 0.101854)
		(layer "F.Cu")
		(net "M_A_CPU0_SA_DQ<1>")
	)
	(segment
		(start 331.953616 -297.63593)
		(end 331.8891 -297.894756)
		(width 0.1016)
		(layer "F.Cu")
		(net "M_A_CPU0_SA_DQ<1>")
	)
	(segment
		(start 311.191402 -314.623958)
		(end 311.034176 -314.466732)
		(width 0.20066)
		(layer "F.Cu")
		(net "M_A_CPU0_SA_DQ<1>")
	)
	(segment
		(start 316.53734 -313.88431)
		(end 315.037724 -314.505594)
		(width 0.20066)
		(layer "F.Cu")
		(net "M_A_CPU0_SA_DQ<1>")
	)
	(segment
		(start 310.77154 -314.466732)
		(end 310.62168 -314.616592)
		(width 0.20066)
		(layer "F.Cu")
		(net "M_A_CPU0_SA_DQ<1>")
	)
	(segment
		(start 302.603408 -314.868306)
		(end 302.837596 -314.634118)
		(width 0.20066)
		(layer "F.Cu")
		(net "M_A_CPU0_SA_DQ<1>")
	)
	(segment
		(start 331.71765 -298.455842)
		(end 331.594206 -298.529502)
		(width 0.1016)
		(layer "F.Cu")
		(net "M_A_CPU0_SA_DQ<1>")
	)
	(segment
		(start 331.717142 -299.12437)
		(end 331.590142 -299.25137)
		(width 0.1016)
		(layer "F.Cu")
		(net "M_A_CPU0_SA_DQ<1>")
	)
	(segment
		(start 314.051696 -315.041534)
		(end 311.984136 -315.041534)
		(width 0.1016)
		(layer "F.Cu")
		(net "M_A_CPU0_SA_DQ<1>")
	)
	(segment
		(start 332.17358 -282.486354)
		(end 332.17358 -297.239182)
		(width 0.1016)
		(layer "F.Cu")
		(net "M_A_CPU0_SA_DQ<1>")
	)
	(segment
		(start 331.8891 -297.894756)
		(end 332.038198 -298.144692)
		(width 0.1016)
		(layer "F.Cu")
		(net "M_A_CPU0_SA_DQ<1>")
	)
	(segment
		(start 314.523882 -314.851288)
		(end 314.32246 -315.05271)
		(width 0.20066)
		(layer "F.Cu")
		(net "M_A_CPU0_SA_DQ<1>")
	)
	(segment
		(start 332.038198 -298.144692)
		(end 331.970888 -298.414186)
		(width 0.1016)
		(layer "F.Cu")
		(net "M_A_CPU0_SA_DQ<1>")
	)
	(segment
		(start 333.152496 -279.84196)
		(end 332.927452 -279.84196)
		(width 0.1016)
		(layer "F.Cu")
		(net "M_A_CPU0_SA_DQ<1>")
	)
	(segment
		(start 332.721966 -280.429208)
		(end 332.670404 -280.687018)
		(width 0.1016)
		(layer "F.Cu")
		(net "M_A_CPU0_SA_DQ<1>")
	)
	(segment
		(start 306.589176 -314.185554)
		(end 306.644294 -314.185554)
		(width 0.101854)
		(layer "F.Cu")
		(net "M_A_CPU0_SA_DQ<1>")
	)
	(segment
		(start 331.846428 -298.488354)
		(end 331.71765 -298.455842)
		(width 0.1016)
		(layer "F.Cu")
		(net "M_A_CPU0_SA_DQ<1>")
	)
	(segment
		(start 304.353214 -314.19165)
		(end 306.58308 -314.19165)
		(width 0.1016)
		(layer "F.Cu")
		(net "M_A_CPU0_SA_DQ<1>")
	)
	(segment
		(start 317.802768 -313.038744)
		(end 316.53734 -313.88431)
		(width 0.20066)
		(layer "F.Cu")
		(net "M_A_CPU0_SA_DQ<1>")
	)
	(segment
		(start 311.191402 -314.891674)
		(end 311.191402 -314.623958)
		(width 0.20066)
		(layer "F.Cu")
		(net "M_A_CPU0_SA_DQ<1>")
	)
	(segment
		(start 314.630562 -314.505594)
		(end 314.523882 -314.612274)
		(width 0.20066)
		(layer "F.Cu")
		(net "M_A_CPU0_SA_DQ<1>")
	)
	(segment
		(start 303.008538 -314.17514)
		(end 304.319178 -314.17514)
		(width 0.20066)
		(layer "F.Cu")
		(net "M_A_CPU0_SA_DQ<1>")
	)
	(segment
		(start 333.231998 -279.762458)
		(end 333.152496 -279.84196)
		(width 0.1016)
		(layer "F.Cu")
		(net "M_A_CPU0_SA_DQ<1>")
	)
	(segment
		(start 302.837596 -314.634118)
		(end 302.837596 -314.346082)
		(width 0.20066)
		(layer "F.Cu")
		(net "M_A_CPU0_SA_DQ<1>")
	)
	(segment
		(start 311.034176 -314.466732)
		(end 310.77154 -314.466732)
		(width 0.20066)
		(layer "F.Cu")
		(net "M_A_CPU0_SA_DQ<1>")
	)
	(segment
		(start 315.037724 -314.505594)
		(end 314.630562 -314.505594)
		(width 0.20066)
		(layer "F.Cu")
		(net "M_A_CPU0_SA_DQ<1>")
	)
	(segment
		(start 333.375762 -279.428194)
		(end 333.231998 -279.571958)
		(width 0.088646)
		(layer "F.Cu")
		(net "M_A_CPU0_SA_DQ<1>")
	)
	(segment
		(start 304.336704 -314.17514)
		(end 304.353214 -314.19165)
		(width 0.101854)
		(layer "F.Cu")
		(net "M_A_CPU0_SA_DQ<1>")
	)
	(segment
		(start 331.590142 -299.25137)
		(end 317.802768 -313.038744)
		(width 0.20066)
		(layer "F.Cu")
		(net "M_A_CPU0_SA_DQ<1>")
	)
	(segment
		(start 306.644294 -314.185554)
		(end 306.950618 -314.185554)
		(width 0.20066)
		(layer "F.Cu")
		(net "M_A_CPU0_SA_DQ<1>")
	)
	(segment
		(start 306.950618 -314.185554)
		(end 307.381656 -314.616592)
		(width 0.20066)
		(layer "F.Cu")
		(net "M_A_CPU0_SA_DQ<1>")
	)
	(segment
		(start 311.973976 -315.051694)
		(end 311.94248 -315.051694)
		(width 0.101854)
		(layer "F.Cu")
		(net "M_A_CPU0_SA_DQ<1>")
	)
	(segment
		(start 332.512162 -280.792428)
		(end 332.17358 -282.486354)
		(width 0.1016)
		(layer "F.Cu")
		(net "M_A_CPU0_SA_DQ<1>")
	)
	(segment
		(start 310.62168 -314.616592)
		(end 308.887114 -314.616592)
		(width 0.20066)
		(layer "F.Cu")
		(net "M_A_CPU0_SA_DQ<1>")
	)
	(segment
		(start 301.967138 -314.616592)
		(end 301.967392 -314.616338)
		(width 0.20066)
		(layer "F.Cu")
		(net "M_A_CPU0_SA_DQ<1>")
	)
	(segment
		(start 311.94248 -315.051694)
		(end 311.351422 -315.051694)
		(width 0.20066)
		(layer "F.Cu")
		(net "M_A_CPU0_SA_DQ<1>")
	)
	(segment
		(start 314.32246 -315.05271)
		(end 314.10148 -315.05271)
		(width 0.20066)
		(layer "F.Cu")
		(net "M_A_CPU0_SA_DQ<1>")
	)
	(segment
		(start 332.616556 -280.270966)
		(end 332.721966 -280.429208)
		(width 0.1016)
		(layer "F.Cu")
		(net "M_A_CPU0_SA_DQ<1>")
	)
	(segment
		(start 334.617568 -272.659094)
		(end 334.433164 -272.552668)
		(width 0.088646)
		(layer "F.Cu")
		(net "M_A_CPU0_SA_DQ<19>")
	)
	(segment
		(start 320.747136 -295.883584)
		(end 320.546476 -295.682924)
		(width 0.20066)
		(layer "F.Cu")
		(net "M_A_CPU0_SA_DQ<19>")
	)
	(segment
		(start 307.76291 -295.507156)
		(end 307.786786 -295.507156)
		(width 0.101854)
		(layer "F.Cu")
		(net "M_A_CPU0_SA_DQ<19>")
	)
	(segment
		(start 332.87335 -273.37766)
		(end 332.710282 -273.37766)
		(width 0.088646)
		(layer "F.Cu")
		(net "M_A_CPU0_SA_DQ<19>")
	)
	(segment
		(start 329.19924 -277.29434)
		(end 328.619866 -278.376126)
		(width 0.1016)
		(layer "F.Cu")
		(net "M_A_CPU0_SA_DQ<19>")
	)
	(segment
		(start 316.990476 -295.682924)
		(end 316.789816 -295.883584)
		(width 0.20066)
		(layer "F.Cu")
		(net "M_A_CPU0_SA_DQ<19>")
	)
	(segment
		(start 333.953612 -272.649188)
		(end 333.953612 -272.927064)
		(width 0.088646)
		(layer "F.Cu")
		(net "M_A_CPU0_SA_DQ<19>")
	)
	(segment
		(start 321.257676 -295.505124)
		(end 321.257676 -295.682924)
		(width 0.20066)
		(layer "F.Cu")
		(net "M_A_CPU0_SA_DQ<19>")
	)
	(segment
		(start 316.279276 -295.682924)
		(end 316.279276 -295.505124)
		(width 0.20066)
		(layer "F.Cu")
		(net "M_A_CPU0_SA_DQ<19>")
	)
	(segment
		(start 325.40448 -294.191944)
		(end 322.718938 -295.304464)
		(width 0.20066)
		(layer "F.Cu")
		(net "M_A_CPU0_SA_DQ<19>")
	)
	(segment
		(start 310.03748 -295.491662)
		(end 310.088026 -295.491662)
		(width 0.101854)
		(layer "F.Cu")
		(net "M_A_CPU0_SA_DQ<19>")
	)
	(segment
		(start 328.619866 -278.376126)
		(end 327.95718 -281.69362)
		(width 0.1016)
		(layer "F.Cu")
		(net "M_A_CPU0_SA_DQ<19>")
	)
	(segment
		(start 319.634616 -295.883584)
		(end 319.324736 -295.883584)
		(width 0.20066)
		(layer "F.Cu")
		(net "M_A_CPU0_SA_DQ<19>")
	)
	(segment
		(start 333.102712 -273.472656)
		(end 332.87335 -273.37766)
		(width 0.088646)
		(layer "F.Cu")
		(net "M_A_CPU0_SA_DQ<19>")
	)
	(segment
		(start 307.409596 -295.507156)
		(end 307.76291 -295.507156)
		(width 0.20066)
		(layer "F.Cu")
		(net "M_A_CPU0_SA_DQ<19>")
	)
	(segment
		(start 307.25491 -295.216834)
		(end 307.25491 -295.35247)
		(width 0.20066)
		(layer "F.Cu")
		(net "M_A_CPU0_SA_DQ<19>")
	)
	(segment
		(start 322.718938 -295.304464)
		(end 321.458336 -295.304464)
		(width 0.20066)
		(layer "F.Cu")
		(net "M_A_CPU0_SA_DQ<19>")
	)
	(segment
		(start 316.789816 -295.883584)
		(end 316.479936 -295.883584)
		(width 0.20066)
		(layer "F.Cu")
		(net "M_A_CPU0_SA_DQ<19>")
	)
	(segment
		(start 327.593198 -292.003226)
		(end 325.40448 -294.191944)
		(width 0.20066)
		(layer "F.Cu")
		(net "M_A_CPU0_SA_DQ<19>")
	)
	(segment
		(start 314.32627 -295.304464)
		(end 314.088526 -295.06672)
		(width 0.20066)
		(layer "F.Cu")
		(net "M_A_CPU0_SA_DQ<19>")
	)
	(segment
		(start 332.362556 -274.131024)
		(end 331.887322 -274.606258)
		(width 0.088646)
		(layer "F.Cu")
		(net "M_A_CPU0_SA_DQ<19>")
	)
	(segment
		(start 333.502508 -273.472656)
		(end 333.102712 -273.472656)
		(width 0.088646)
		(layer "F.Cu")
		(net "M_A_CPU0_SA_DQ<19>")
	)
	(segment
		(start 319.835276 -295.682924)
		(end 319.634616 -295.883584)
		(width 0.20066)
		(layer "F.Cu")
		(net "M_A_CPU0_SA_DQ<19>")
	)
	(segment
		(start 319.835276 -295.505124)
		(end 319.835276 -295.682924)
		(width 0.20066)
		(layer "F.Cu")
		(net "M_A_CPU0_SA_DQ<19>")
	)
	(segment
		(start 310.698896 -295.141904)
		(end 311.109106 -295.141904)
		(width 0.20066)
		(layer "F.Cu")
		(net "M_A_CPU0_SA_DQ<19>")
	)
	(segment
		(start 312.159142 -295.06672)
		(end 312.987182 -295.06672)
		(width 0.20066)
		(layer "F.Cu")
		(net "M_A_CPU0_SA_DQ<19>")
	)
	(segment
		(start 318.412876 -295.505124)
		(end 318.412876 -295.682924)
		(width 0.20066)
		(layer "F.Cu")
		(net "M_A_CPU0_SA_DQ<19>")
	)
	(segment
		(start 318.212216 -295.883584)
		(end 317.902336 -295.883584)
		(width 0.20066)
		(layer "F.Cu")
		(net "M_A_CPU0_SA_DQ<19>")
	)
	(segment
		(start 307.25491 -295.35247)
		(end 307.409596 -295.507156)
		(width 0.20066)
		(layer "F.Cu")
		(net "M_A_CPU0_SA_DQ<19>")
	)
	(segment
		(start 327.95718 -281.69362)
		(end 327.95718 -291.639244)
		(width 0.1016)
		(layer "F.Cu")
		(net "M_A_CPU0_SA_DQ<19>")
	)
	(segment
		(start 310.088026 -295.491662)
		(end 310.349138 -295.491662)
		(width 0.20066)
		(layer "F.Cu")
		(net "M_A_CPU0_SA_DQ<19>")
	)
	(segment
		(start 314.088526 -295.06672)
		(end 312.987182 -295.06672)
		(width 0.20066)
		(layer "F.Cu")
		(net "M_A_CPU0_SA_DQ<19>")
	)
	(segment
		(start 334.307434 -272.518886)
		(end 334.083914 -272.518886)
		(width 0.088646)
		(layer "F.Cu")
		(net "M_A_CPU0_SA_DQ<19>")
	)
	(segment
		(start 332.710282 -273.37766)
		(end 332.582774 -273.430492)
		(width 0.088646)
		(layer "F.Cu")
		(net "M_A_CPU0_SA_DQ<19>")
	)
	(segment
		(start 307.104796 -295.06672)
		(end 307.25491 -295.216834)
		(width 0.20066)
		(layer "F.Cu")
		(net "M_A_CPU0_SA_DQ<19>")
	)
	(segment
		(start 320.546476 -295.682924)
		(end 320.546476 -295.505124)
		(width 0.20066)
		(layer "F.Cu")
		(net "M_A_CPU0_SA_DQ<19>")
	)
	(segment
		(start 321.257676 -295.682924)
		(end 321.057016 -295.883584)
		(width 0.20066)
		(layer "F.Cu")
		(net "M_A_CPU0_SA_DQ<19>")
	)
	(segment
		(start 334.996028 -272.820384)
		(end 334.617568 -272.659094)
		(width 0.088646)
		(layer "F.Cu")
		(net "M_A_CPU0_SA_DQ<19>")
	)
	(segment
		(start 319.124076 -295.505124)
		(end 318.923416 -295.304464)
		(width 0.20066)
		(layer "F.Cu")
		(net "M_A_CPU0_SA_DQ<19>")
	)
	(segment
		(start 320.345816 -295.304464)
		(end 320.035936 -295.304464)
		(width 0.20066)
		(layer "F.Cu")
		(net "M_A_CPU0_SA_DQ<19>")
	)
	(segment
		(start 307.80228 -295.491662)
		(end 310.03748 -295.491662)
		(width 0.1016)
		(layer "F.Cu")
		(net "M_A_CPU0_SA_DQ<19>")
	)
	(segment
		(start 320.035936 -295.304464)
		(end 319.835276 -295.505124)
		(width 0.20066)
		(layer "F.Cu")
		(net "M_A_CPU0_SA_DQ<19>")
	)
	(segment
		(start 327.95718 -291.639244)
		(end 327.593198 -292.003226)
		(width 0.1016)
		(layer "F.Cu")
		(net "M_A_CPU0_SA_DQ<19>")
	)
	(segment
		(start 321.458336 -295.304464)
		(end 321.257676 -295.505124)
		(width 0.20066)
		(layer "F.Cu")
		(net "M_A_CPU0_SA_DQ<19>")
	)
	(segment
		(start 318.923416 -295.304464)
		(end 318.613536 -295.304464)
		(width 0.20066)
		(layer "F.Cu")
		(net "M_A_CPU0_SA_DQ<19>")
	)
	(segment
		(start 305.443382 -295.06672)
		(end 307.104796 -295.06672)
		(width 0.20066)
		(layer "F.Cu")
		(net "M_A_CPU0_SA_DQ<19>")
	)
	(segment
		(start 317.501016 -295.304464)
		(end 317.191136 -295.304464)
		(width 0.20066)
		(layer "F.Cu")
		(net "M_A_CPU0_SA_DQ<19>")
	)
	(segment
		(start 334.083914 -272.518886)
		(end 333.953612 -272.649188)
		(width 0.088646)
		(layer "F.Cu")
		(net "M_A_CPU0_SA_DQ<19>")
	)
	(segment
		(start 316.078616 -295.304464)
		(end 314.32627 -295.304464)
		(width 0.20066)
		(layer "F.Cu")
		(net "M_A_CPU0_SA_DQ<19>")
	)
	(segment
		(start 332.362556 -273.81581)
		(end 332.362556 -274.131024)
		(width 0.088646)
		(layer "F.Cu")
		(net "M_A_CPU0_SA_DQ<19>")
	)
	(segment
		(start 319.124076 -295.682924)
		(end 319.124076 -295.505124)
		(width 0.20066)
		(layer "F.Cu")
		(net "M_A_CPU0_SA_DQ<19>")
	)
	(segment
		(start 317.701676 -295.505124)
		(end 317.501016 -295.304464)
		(width 0.20066)
		(layer "F.Cu")
		(net "M_A_CPU0_SA_DQ<19>")
	)
	(segment
		(start 311.109106 -295.141904)
		(end 311.458864 -295.491662)
		(width 0.20066)
		(layer "F.Cu")
		(net "M_A_CPU0_SA_DQ<19>")
	)
	(segment
		(start 311.458864 -295.491662)
		(end 311.7342 -295.491662)
		(width 0.20066)
		(layer "F.Cu")
		(net "M_A_CPU0_SA_DQ<19>")
	)
	(segment
		(start 332.479396 -273.53387)
		(end 332.362556 -273.81581)
		(width 0.088646)
		(layer "F.Cu")
		(net "M_A_CPU0_SA_DQ<19>")
	)
	(segment
		(start 319.324736 -295.883584)
		(end 319.124076 -295.682924)
		(width 0.20066)
		(layer "F.Cu")
		(net "M_A_CPU0_SA_DQ<19>")
	)
	(segment
		(start 310.349138 -295.491662)
		(end 310.698896 -295.141904)
		(width 0.20066)
		(layer "F.Cu")
		(net "M_A_CPU0_SA_DQ<19>")
	)
	(segment
		(start 321.057016 -295.883584)
		(end 320.747136 -295.883584)
		(width 0.20066)
		(layer "F.Cu")
		(net "M_A_CPU0_SA_DQ<19>")
	)
	(segment
		(start 320.546476 -295.505124)
		(end 320.345816 -295.304464)
		(width 0.20066)
		(layer "F.Cu")
		(net "M_A_CPU0_SA_DQ<19>")
	)
	(segment
		(start 316.479936 -295.883584)
		(end 316.279276 -295.682924)
		(width 0.20066)
		(layer "F.Cu")
		(net "M_A_CPU0_SA_DQ<19>")
	)
	(segment
		(start 331.887322 -274.606258)
		(end 329.19924 -277.29434)
		(width 0.1016)
		(layer "F.Cu")
		(net "M_A_CPU0_SA_DQ<19>")
	)
	(segment
		(start 317.701676 -295.682924)
		(end 317.701676 -295.505124)
		(width 0.20066)
		(layer "F.Cu")
		(net "M_A_CPU0_SA_DQ<19>")
	)
	(segment
		(start 335.255362 -272.917158)
		(end 334.996028 -272.820384)
		(width 0.088646)
		(layer "F.Cu")
		(net "M_A_CPU0_SA_DQ<19>")
	)
	(segment
		(start 333.677768 -273.39544)
		(end 333.658464 -273.406616)
		(width 0.088646)
		(layer "F.Cu")
		(net "M_A_CPU0_SA_DQ<19>")
	)
	(segment
		(start 317.191136 -295.304464)
		(end 316.990476 -295.505124)
		(width 0.20066)
		(layer "F.Cu")
		(net "M_A_CPU0_SA_DQ<19>")
	)
	(segment
		(start 316.279276 -295.505124)
		(end 316.078616 -295.304464)
		(width 0.20066)
		(layer "F.Cu")
		(net "M_A_CPU0_SA_DQ<19>")
	)
	(segment
		(start 332.582774 -273.430492)
		(end 332.479396 -273.53387)
		(width 0.088646)
		(layer "F.Cu")
		(net "M_A_CPU0_SA_DQ<19>")
	)
	(segment
		(start 318.412876 -295.682924)
		(end 318.212216 -295.883584)
		(width 0.20066)
		(layer "F.Cu")
		(net "M_A_CPU0_SA_DQ<19>")
	)
	(segment
		(start 316.990476 -295.505124)
		(end 316.990476 -295.682924)
		(width 0.20066)
		(layer "F.Cu")
		(net "M_A_CPU0_SA_DQ<19>")
	)
	(segment
		(start 317.902336 -295.883584)
		(end 317.701676 -295.682924)
		(width 0.20066)
		(layer "F.Cu")
		(net "M_A_CPU0_SA_DQ<19>")
	)
	(segment
		(start 318.613536 -295.304464)
		(end 318.412876 -295.505124)
		(width 0.20066)
		(layer "F.Cu")
		(net "M_A_CPU0_SA_DQ<19>")
	)
	(segment
		(start 311.7342 -295.491662)
		(end 312.159142 -295.06672)
		(width 0.20066)
		(layer "F.Cu")
		(net "M_A_CPU0_SA_DQ<19>")
	)
	(segment
		(start 307.786786 -295.507156)
		(end 307.80228 -295.491662)
		(width 0.101854)
		(layer "F.Cu")
		(net "M_A_CPU0_SA_DQ<19>")
	)
	(arc
		(start 333.953612 -272.927064)
		(mid 333.877331 -273.197554)
		(end 333.677768 -273.39544)
		(width 0.088646)
		(layer "F.Cu")
		(net "M_A_CPU0_SA_DQ<19>")
	)
	(arc
		(start 333.527146 -273.468338)
		(mid 333.51502 -273.471588)
		(end 333.502508 -273.472656)
		(width 0.088646)
		(layer "F.Cu")
		(net "M_A_CPU0_SA_DQ<19>")
	)
	(arc
		(start 333.658464 -273.406616)
		(mid 333.594121 -273.440276)
		(end 333.527146 -273.468338)
		(width 0.088646)
		(layer "F.Cu")
		(net "M_A_CPU0_SA_DQ<19>")
	)
	(arc
		(start 334.433164 -272.552668)
		(mid 334.372526 -272.527477)
		(end 334.307434 -272.518886)
		(width 0.088646)
		(layer "F.Cu")
		(net "M_A_CPU0_SA_DQ<19>")
	)
	(segment
		(start 318.627252 -297.393614)
		(end 318.426592 -297.594274)
		(width 0.20066)
		(layer "F.Cu")
		(net "M_A_CPU0_SA_DQ<18>")
	)
	(segment
		(start 316.694312 -297.594274)
		(end 316.493652 -297.393614)
		(width 0.20066)
		(layer "F.Cu")
		(net "M_A_CPU0_SA_DQ<18>")
	)
	(segment
		(start 322.931536 -297.163236)
		(end 322.812156 -296.874692)
		(width 0.20066)
		(layer "F.Cu")
		(net "M_A_CPU0_SA_DQ<18>")
	)
	(segment
		(start 317.204852 -297.393614)
		(end 317.004192 -297.594274)
		(width 0.20066)
		(layer "F.Cu")
		(net "M_A_CPU0_SA_DQ<18>")
	)
	(segment
		(start 332.820264 -274.522692)
		(end 332.820264 -274.539202)
		(width 0.088646)
		(layer "F.Cu")
		(net "M_A_CPU0_SA_DQ<18>")
	)
	(segment
		(start 311.259474 -296.864532)
		(end 311.357264 -296.766742)
		(width 0.20066)
		(layer "F.Cu")
		(net "M_A_CPU0_SA_DQ<18>")
	)
	(segment
		(start 307.80228 -296.341546)
		(end 310.03748 -296.341546)
		(width 0.1016)
		(layer "F.Cu")
		(net "M_A_CPU0_SA_DQ<18>")
	)
	(segment
		(start 317.715392 -297.163998)
		(end 317.405512 -297.163998)
		(width 0.20066)
		(layer "F.Cu")
		(net "M_A_CPU0_SA_DQ<18>")
	)
	(segment
		(start 333.772002 -274.762722)
		(end 333.746094 -274.502626)
		(width 0.088646)
		(layer "F.Cu")
		(net "M_A_CPU0_SA_DQ<18>")
	)
	(segment
		(start 328.41184 -292.999922)
		(end 326.126856 -295.284906)
		(width 0.20066)
		(layer "F.Cu")
		(net "M_A_CPU0_SA_DQ<18>")
	)
	(segment
		(start 326.126856 -295.284906)
		(end 324.891908 -295.795954)
		(width 0.20066)
		(layer "F.Cu")
		(net "M_A_CPU0_SA_DQ<18>")
	)
	(segment
		(start 323.588634 -296.890694)
		(end 323.480176 -297.152822)
		(width 0.20066)
		(layer "F.Cu")
		(net "M_A_CPU0_SA_DQ<18>")
	)
	(segment
		(start 307.236876 -296.327322)
		(end 307.76291 -296.327322)
		(width 0.20066)
		(layer "F.Cu")
		(net "M_A_CPU0_SA_DQ<18>")
	)
	(segment
		(start 317.916052 -297.364658)
		(end 317.715392 -297.163998)
		(width 0.20066)
		(layer "F.Cu")
		(net "M_A_CPU0_SA_DQ<18>")
	)
	(segment
		(start 310.457088 -296.722038)
		(end 310.703722 -296.968672)
		(width 0.20066)
		(layer "F.Cu")
		(net "M_A_CPU0_SA_DQ<18>")
	)
	(segment
		(start 319.338452 -297.393614)
		(end 319.338452 -297.364658)
		(width 0.20066)
		(layer "F.Cu")
		(net "M_A_CPU0_SA_DQ<18>")
	)
	(segment
		(start 333.86522 -274.847304)
		(end 333.772002 -274.762722)
		(width 0.088646)
		(layer "F.Cu")
		(net "M_A_CPU0_SA_DQ<18>")
	)
	(segment
		(start 320.250312 -297.163998)
		(end 320.049652 -297.364658)
		(width 0.20066)
		(layer "F.Cu")
		(net "M_A_CPU0_SA_DQ<18>")
	)
	(segment
		(start 306.940458 -296.766742)
		(end 307.04282 -296.66438)
		(width 0.20066)
		(layer "F.Cu")
		(net "M_A_CPU0_SA_DQ<18>")
	)
	(segment
		(start 310.457088 -296.482516)
		(end 310.457088 -296.722038)
		(width 0.20066)
		(layer "F.Cu")
		(net "M_A_CPU0_SA_DQ<18>")
	)
	(segment
		(start 316.292992 -297.163998)
		(end 315.492638 -297.163998)
		(width 0.20066)
		(layer "F.Cu")
		(net "M_A_CPU0_SA_DQ<18>")
	)
	(segment
		(start 324.891908 -295.795954)
		(end 324.78345 -296.057828)
		(width 0.20066)
		(layer "F.Cu")
		(net "M_A_CPU0_SA_DQ<18>")
	)
	(segment
		(start 316.493652 -297.364658)
		(end 316.292992 -297.163998)
		(width 0.20066)
		(layer "F.Cu")
		(net "M_A_CPU0_SA_DQ<18>")
	)
	(segment
		(start 323.577712 -296.34053)
		(end 323.469254 -296.602404)
		(width 0.20066)
		(layer "F.Cu")
		(net "M_A_CPU0_SA_DQ<18>")
	)
	(segment
		(start 318.827912 -297.163998)
		(end 318.627252 -297.364658)
		(width 0.20066)
		(layer "F.Cu")
		(net "M_A_CPU0_SA_DQ<18>")
	)
	(segment
		(start 329.201018 -278.584406)
		(end 328.56678 -281.756358)
		(width 0.1016)
		(layer "F.Cu")
		(net "M_A_CPU0_SA_DQ<18>")
	)
	(segment
		(start 307.76291 -296.327322)
		(end 307.788056 -296.327322)
		(width 0.101854)
		(layer "F.Cu")
		(net "M_A_CPU0_SA_DQ<18>")
	)
	(segment
		(start 322.812156 -296.874692)
		(end 322.550282 -296.766234)
		(width 0.20066)
		(layer "F.Cu")
		(net "M_A_CPU0_SA_DQ<18>")
	)
	(segment
		(start 320.049652 -297.364658)
		(end 320.049652 -297.393614)
		(width 0.20066)
		(layer "F.Cu")
		(net "M_A_CPU0_SA_DQ<18>")
	)
	(segment
		(start 328.56678 -281.756358)
		(end 328.56678 -292.844982)
		(width 0.1016)
		(layer "F.Cu")
		(net "M_A_CPU0_SA_DQ<18>")
	)
	(segment
		(start 317.916052 -297.393614)
		(end 317.916052 -297.364658)
		(width 0.20066)
		(layer "F.Cu")
		(net "M_A_CPU0_SA_DQ<18>")
	)
	(segment
		(start 334.016604 -274.843748)
		(end 333.86522 -274.847304)
		(width 0.088646)
		(layer "F.Cu")
		(net "M_A_CPU0_SA_DQ<18>")
	)
	(segment
		(start 319.848992 -297.594274)
		(end 319.539112 -297.594274)
		(width 0.20066)
		(layer "F.Cu")
		(net "M_A_CPU0_SA_DQ<18>")
	)
	(segment
		(start 333.207106 -274.20824)
		(end 333.083408 -274.259548)
		(width 0.088646)
		(layer "F.Cu")
		(net "M_A_CPU0_SA_DQ<18>")
	)
	(segment
		(start 320.049652 -297.393614)
		(end 319.848992 -297.594274)
		(width 0.20066)
		(layer "F.Cu")
		(net "M_A_CPU0_SA_DQ<18>")
	)
	(segment
		(start 318.116712 -297.594274)
		(end 317.916052 -297.393614)
		(width 0.20066)
		(layer "F.Cu")
		(net "M_A_CPU0_SA_DQ<18>")
	)
	(segment
		(start 319.137792 -297.163998)
		(end 318.827912 -297.163998)
		(width 0.20066)
		(layer "F.Cu")
		(net "M_A_CPU0_SA_DQ<18>")
	)
	(segment
		(start 329.692 -277.667466)
		(end 329.201018 -278.584406)
		(width 0.1016)
		(layer "F.Cu")
		(net "M_A_CPU0_SA_DQ<18>")
	)
	(segment
		(start 319.338452 -297.364658)
		(end 319.137792 -297.163998)
		(width 0.20066)
		(layer "F.Cu")
		(net "M_A_CPU0_SA_DQ<18>")
	)
	(segment
		(start 322.550282 -296.766234)
		(end 321.590162 -297.163998)
		(width 0.20066)
		(layer "F.Cu")
		(net "M_A_CPU0_SA_DQ<18>")
	)
	(segment
		(start 307.04282 -296.66438)
		(end 307.04282 -296.521378)
		(width 0.20066)
		(layer "F.Cu")
		(net "M_A_CPU0_SA_DQ<18>")
	)
	(segment
		(start 318.627252 -297.364658)
		(end 318.627252 -297.393614)
		(width 0.20066)
		(layer "F.Cu")
		(net "M_A_CPU0_SA_DQ<18>")
	)
	(segment
		(start 321.590162 -297.163998)
		(end 320.250312 -297.163998)
		(width 0.20066)
		(layer "F.Cu")
		(net "M_A_CPU0_SA_DQ<18>")
	)
	(segment
		(start 332.320392 -275.039074)
		(end 329.692 -277.667466)
		(width 0.1016)
		(layer "F.Cu")
		(net "M_A_CPU0_SA_DQ<18>")
	)
	(segment
		(start 333.492602 -274.20824)
		(end 333.207106 -274.20824)
		(width 0.088646)
		(layer "F.Cu")
		(net "M_A_CPU0_SA_DQ<18>")
	)
	(segment
		(start 324.78345 -296.057828)
		(end 324.90283 -296.346118)
		(width 0.20066)
		(layer "F.Cu")
		(net "M_A_CPU0_SA_DQ<18>")
	)
	(segment
		(start 316.493652 -297.393614)
		(end 316.493652 -297.364658)
		(width 0.20066)
		(layer "F.Cu")
		(net "M_A_CPU0_SA_DQ<18>")
	)
	(segment
		(start 310.03748 -296.341546)
		(end 310.088026 -296.341546)
		(width 0.101854)
		(layer "F.Cu")
		(net "M_A_CPU0_SA_DQ<18>")
	)
	(segment
		(start 315.095382 -296.766742)
		(end 312.987182 -296.766742)
		(width 0.20066)
		(layer "F.Cu")
		(net "M_A_CPU0_SA_DQ<18>")
	)
	(segment
		(start 310.703722 -296.968672)
		(end 311.008014 -296.968672)
		(width 0.20066)
		(layer "F.Cu")
		(net "M_A_CPU0_SA_DQ<18>")
	)
	(segment
		(start 317.405512 -297.163998)
		(end 317.204852 -297.364658)
		(width 0.20066)
		(layer "F.Cu")
		(net "M_A_CPU0_SA_DQ<18>")
	)
	(segment
		(start 319.539112 -297.594274)
		(end 319.338452 -297.393614)
		(width 0.20066)
		(layer "F.Cu")
		(net "M_A_CPU0_SA_DQ<18>")
	)
	(segment
		(start 332.820264 -274.539202)
		(end 332.320392 -275.039074)
		(width 0.088646)
		(layer "F.Cu")
		(net "M_A_CPU0_SA_DQ<18>")
	)
	(segment
		(start 307.04282 -296.521378)
		(end 307.236876 -296.327322)
		(width 0.20066)
		(layer "F.Cu")
		(net "M_A_CPU0_SA_DQ<18>")
	)
	(segment
		(start 323.19341 -297.271694)
		(end 322.931536 -297.163236)
		(width 0.20066)
		(layer "F.Cu")
		(net "M_A_CPU0_SA_DQ<18>")
	)
	(segment
		(start 317.204852 -297.364658)
		(end 317.204852 -297.393614)
		(width 0.20066)
		(layer "F.Cu")
		(net "M_A_CPU0_SA_DQ<18>")
	)
	(segment
		(start 318.426592 -297.594274)
		(end 318.116712 -297.594274)
		(width 0.20066)
		(layer "F.Cu")
		(net "M_A_CPU0_SA_DQ<18>")
	)
	(segment
		(start 307.788056 -296.327322)
		(end 307.80228 -296.341546)
		(width 0.101854)
		(layer "F.Cu")
		(net "M_A_CPU0_SA_DQ<18>")
	)
	(segment
		(start 311.357264 -296.766742)
		(end 312.987182 -296.766742)
		(width 0.20066)
		(layer "F.Cu")
		(net "M_A_CPU0_SA_DQ<18>")
	)
	(segment
		(start 323.480176 -297.152822)
		(end 323.19341 -297.271694)
		(width 0.20066)
		(layer "F.Cu")
		(net "M_A_CPU0_SA_DQ<18>")
	)
	(segment
		(start 310.316118 -296.341546)
		(end 310.457088 -296.482516)
		(width 0.20066)
		(layer "F.Cu")
		(net "M_A_CPU0_SA_DQ<18>")
	)
	(segment
		(start 324.90283 -296.346118)
		(end 324.794372 -296.608246)
		(width 0.20066)
		(layer "F.Cu")
		(net "M_A_CPU0_SA_DQ<18>")
	)
	(segment
		(start 324.794372 -296.608246)
		(end 324.507606 -296.727118)
		(width 0.20066)
		(layer "F.Cu")
		(net "M_A_CPU0_SA_DQ<18>")
	)
	(segment
		(start 324.507606 -296.727118)
		(end 324.245732 -296.61866)
		(width 0.20066)
		(layer "F.Cu")
		(net "M_A_CPU0_SA_DQ<18>")
	)
	(segment
		(start 324.245732 -296.61866)
		(end 324.126352 -296.330116)
		(width 0.20066)
		(layer "F.Cu")
		(net "M_A_CPU0_SA_DQ<18>")
	)
	(segment
		(start 333.695294 -274.324826)
		(end 333.575406 -274.235672)
		(width 0.088646)
		(layer "F.Cu")
		(net "M_A_CPU0_SA_DQ<18>")
	)
	(segment
		(start 311.008014 -296.968672)
		(end 311.259474 -296.864532)
		(width 0.20066)
		(layer "F.Cu")
		(net "M_A_CPU0_SA_DQ<18>")
	)
	(segment
		(start 317.004192 -297.594274)
		(end 316.694312 -297.594274)
		(width 0.20066)
		(layer "F.Cu")
		(net "M_A_CPU0_SA_DQ<18>")
	)
	(segment
		(start 334.315562 -274.54479)
		(end 334.016604 -274.843748)
		(width 0.088646)
		(layer "F.Cu")
		(net "M_A_CPU0_SA_DQ<18>")
	)
	(segment
		(start 305.443382 -296.766742)
		(end 306.940458 -296.766742)
		(width 0.20066)
		(layer "F.Cu")
		(net "M_A_CPU0_SA_DQ<18>")
	)
	(segment
		(start 333.746094 -274.502626)
		(end 333.746094 -274.426426)
		(width 0.088646)
		(layer "F.Cu")
		(net "M_A_CPU0_SA_DQ<18>")
	)
	(segment
		(start 315.492638 -297.163998)
		(end 315.095382 -296.766742)
		(width 0.20066)
		(layer "F.Cu")
		(net "M_A_CPU0_SA_DQ<18>")
	)
	(segment
		(start 333.746094 -274.426426)
		(end 333.695294 -274.324826)
		(width 0.088646)
		(layer "F.Cu")
		(net "M_A_CPU0_SA_DQ<18>")
	)
	(segment
		(start 328.56678 -292.844982)
		(end 328.41184 -292.999922)
		(width 0.1016)
		(layer "F.Cu")
		(net "M_A_CPU0_SA_DQ<18>")
	)
	(segment
		(start 323.469254 -296.602404)
		(end 323.588634 -296.890694)
		(width 0.20066)
		(layer "F.Cu")
		(net "M_A_CPU0_SA_DQ<18>")
	)
	(segment
		(start 324.126352 -296.330116)
		(end 323.864478 -296.221658)
		(width 0.20066)
		(layer "F.Cu")
		(net "M_A_CPU0_SA_DQ<18>")
	)
	(segment
		(start 323.864478 -296.221658)
		(end 323.577712 -296.34053)
		(width 0.20066)
		(layer "F.Cu")
		(net "M_A_CPU0_SA_DQ<18>")
	)
	(segment
		(start 310.088026 -296.341546)
		(end 310.316118 -296.341546)
		(width 0.20066)
		(layer "F.Cu")
		(net "M_A_CPU0_SA_DQ<18>")
	)
	(segment
		(start 333.083408 -274.259548)
		(end 332.820264 -274.522692)
		(width 0.088646)
		(layer "F.Cu")
		(net "M_A_CPU0_SA_DQ<18>")
	)
	(arc
		(start 333.575406 -274.235672)
		(mid 333.536209 -274.215312)
		(end 333.492602 -274.20824)
		(width 0.088646)
		(layer "F.Cu")
		(net "M_A_CPU0_SA_DQ<18>")
	)
	(segment
		(start 306.786788 -295.491662)
		(end 307.21173 -295.916604)
		(width 0.20066)
		(layer "F.Cu")
		(net "M_A_CPU0_SA_DQ<17>")
	)
	(segment
		(start 314.2361 -296.344848)
		(end 314.232036 -296.348912)
		(width 0.20066)
		(layer "F.Cu")
		(net "M_A_CPU0_SA_DQ<17>")
	)
	(segment
		(start 332.104746 -274.823428)
		(end 329.44435 -277.483824)
		(width 0.1016)
		(layer "F.Cu")
		(net "M_A_CPU0_SA_DQ<17>")
	)
	(segment
		(start 314.232036 -296.348912)
		(end 314.12688 -296.348912)
		(width 0.20066)
		(layer "F.Cu")
		(net "M_A_CPU0_SA_DQ<17>")
	)
	(segment
		(start 314.083192 -296.341546)
		(end 312.003948 -296.341546)
		(width 0.1016)
		(layer "F.Cu")
		(net "M_A_CPU0_SA_DQ<17>")
	)
	(segment
		(start 303.038002 -295.471342)
		(end 304.319178 -295.471342)
		(width 0.20066)
		(layer "F.Cu")
		(net "M_A_CPU0_SA_DQ<17>")
	)
	(segment
		(start 325.773542 -294.733472)
		(end 321.449954 -296.524426)
		(width 0.20066)
		(layer "F.Cu")
		(net "M_A_CPU0_SA_DQ<17>")
	)
	(segment
		(start 311.984644 -296.36085)
		(end 311.91708 -296.36085)
		(width 0.101854)
		(layer "F.Cu")
		(net "M_A_CPU0_SA_DQ<17>")
	)
	(segment
		(start 302.21936 -296.168318)
		(end 302.603408 -296.168318)
		(width 0.20066)
		(layer "F.Cu")
		(net "M_A_CPU0_SA_DQ<17>")
	)
	(segment
		(start 328.911204 -278.47798)
		(end 328.26198 -281.726132)
		(width 0.1016)
		(layer "F.Cu")
		(net "M_A_CPU0_SA_DQ<17>")
	)
	(segment
		(start 321.449954 -296.524426)
		(end 315.89599 -296.524426)
		(width 0.20066)
		(layer "F.Cu")
		(net "M_A_CPU0_SA_DQ<17>")
	)
	(segment
		(start 301.343314 -295.916604)
		(end 301.967138 -295.916604)
		(width 0.20066)
		(layer "F.Cu")
		(net "M_A_CPU0_SA_DQ<17>")
	)
	(segment
		(start 304.348642 -295.471342)
		(end 304.368962 -295.491662)
		(width 0.101854)
		(layer "F.Cu")
		(net "M_A_CPU0_SA_DQ<17>")
	)
	(segment
		(start 306.644294 -295.491662)
		(end 306.786788 -295.491662)
		(width 0.20066)
		(layer "F.Cu")
		(net "M_A_CPU0_SA_DQ<17>")
	)
	(segment
		(start 314.27547 -296.344848)
		(end 314.2361 -296.344848)
		(width 0.20066)
		(layer "F.Cu")
		(net "M_A_CPU0_SA_DQ<17>")
	)
	(segment
		(start 304.368962 -295.491662)
		(end 306.58308 -295.491662)
		(width 0.1016)
		(layer "F.Cu")
		(net "M_A_CPU0_SA_DQ<17>")
	)
	(segment
		(start 301.967138 -295.916604)
		(end 301.967392 -295.91635)
		(width 0.20066)
		(layer "F.Cu")
		(net "M_A_CPU0_SA_DQ<17>")
	)
	(segment
		(start 311.428384 -296.36085)
		(end 310.355996 -295.916604)
		(width 0.20066)
		(layer "F.Cu")
		(net "M_A_CPU0_SA_DQ<17>")
	)
	(segment
		(start 310.355996 -295.916604)
		(end 308.887114 -295.916604)
		(width 0.20066)
		(layer "F.Cu")
		(net "M_A_CPU0_SA_DQ<17>")
	)
	(segment
		(start 302.837596 -295.93413)
		(end 302.837596 -295.671748)
		(width 0.20066)
		(layer "F.Cu")
		(net "M_A_CPU0_SA_DQ<17>")
	)
	(segment
		(start 302.603408 -296.168318)
		(end 302.837596 -295.93413)
		(width 0.20066)
		(layer "F.Cu")
		(net "M_A_CPU0_SA_DQ<17>")
	)
	(segment
		(start 332.47965 -274.574762)
		(end 332.264004 -274.66417)
		(width 0.088646)
		(layer "F.Cu")
		(net "M_A_CPU0_SA_DQ<17>")
	)
	(segment
		(start 332.264004 -274.66417)
		(end 332.104746 -274.823428)
		(width 0.088646)
		(layer "F.Cu")
		(net "M_A_CPU0_SA_DQ<17>")
	)
	(segment
		(start 314.544964 -296.075354)
		(end 314.27547 -296.344848)
		(width 0.20066)
		(layer "F.Cu")
		(net "M_A_CPU0_SA_DQ<17>")
	)
	(segment
		(start 301.967392 -295.91635)
		(end 302.21936 -296.168318)
		(width 0.20066)
		(layer "F.Cu")
		(net "M_A_CPU0_SA_DQ<17>")
	)
	(segment
		(start 315.446918 -296.075354)
		(end 314.544964 -296.075354)
		(width 0.20066)
		(layer "F.Cu")
		(net "M_A_CPU0_SA_DQ<17>")
	)
	(segment
		(start 306.58308 -295.491662)
		(end 306.644294 -295.491662)
		(width 0.101854)
		(layer "F.Cu")
		(net "M_A_CPU0_SA_DQ<17>")
	)
	(segment
		(start 302.837596 -295.671748)
		(end 303.038002 -295.471342)
		(width 0.20066)
		(layer "F.Cu")
		(net "M_A_CPU0_SA_DQ<17>")
	)
	(segment
		(start 314.090558 -296.348912)
		(end 314.083192 -296.341546)
		(width 0.101854)
		(layer "F.Cu")
		(net "M_A_CPU0_SA_DQ<17>")
	)
	(segment
		(start 332.961742 -274.09267)
		(end 332.47965 -274.574762)
		(width 0.088646)
		(layer "F.Cu")
		(net "M_A_CPU0_SA_DQ<17>")
	)
	(segment
		(start 311.91708 -296.36085)
		(end 311.428384 -296.36085)
		(width 0.20066)
		(layer "F.Cu")
		(net "M_A_CPU0_SA_DQ<17>")
	)
	(segment
		(start 328.048366 -292.458648)
		(end 325.773542 -294.733472)
		(width 0.20066)
		(layer "F.Cu")
		(net "M_A_CPU0_SA_DQ<17>")
	)
	(segment
		(start 307.21173 -295.916604)
		(end 308.887114 -295.916604)
		(width 0.20066)
		(layer "F.Cu")
		(net "M_A_CPU0_SA_DQ<17>")
	)
	(segment
		(start 314.12688 -296.348912)
		(end 314.090558 -296.348912)
		(width 0.101854)
		(layer "F.Cu")
		(net "M_A_CPU0_SA_DQ<17>")
	)
	(segment
		(start 304.319178 -295.471342)
		(end 304.348642 -295.471342)
		(width 0.101854)
		(layer "F.Cu")
		(net "M_A_CPU0_SA_DQ<17>")
	)
	(segment
		(start 315.89599 -296.524426)
		(end 315.446918 -296.075354)
		(width 0.20066)
		(layer "F.Cu")
		(net "M_A_CPU0_SA_DQ<17>")
	)
	(segment
		(start 334.46593 -273.94789)
		(end 334.149954 -274.084034)
		(width 0.088646)
		(layer "F.Cu")
		(net "M_A_CPU0_SA_DQ<17>")
	)
	(segment
		(start 329.44435 -277.483824)
		(end 328.911204 -278.47798)
		(width 0.1016)
		(layer "F.Cu")
		(net "M_A_CPU0_SA_DQ<17>")
	)
	(segment
		(start 328.26198 -292.245034)
		(end 328.048366 -292.458648)
		(width 0.1016)
		(layer "F.Cu")
		(net "M_A_CPU0_SA_DQ<17>")
	)
	(segment
		(start 333.142082 -274.017994)
		(end 332.961742 -274.09267)
		(width 0.088646)
		(layer "F.Cu")
		(net "M_A_CPU0_SA_DQ<17>")
	)
	(segment
		(start 333.519018 -274.017994)
		(end 333.142082 -274.017994)
		(width 0.088646)
		(layer "F.Cu")
		(net "M_A_CPU0_SA_DQ<17>")
	)
	(segment
		(start 328.26198 -281.726132)
		(end 328.26198 -292.245034)
		(width 0.1016)
		(layer "F.Cu")
		(net "M_A_CPU0_SA_DQ<17>")
	)
	(segment
		(start 312.003948 -296.341546)
		(end 311.984644 -296.36085)
		(width 0.101854)
		(layer "F.Cu")
		(net "M_A_CPU0_SA_DQ<17>")
	)
	(arc
		(start 334.149954 -274.084034)
		(mid 333.900807 -274.127884)
		(end 333.658464 -274.055332)
		(width 0.088646)
		(layer "F.Cu")
		(net "M_A_CPU0_SA_DQ<17>")
	)
	(arc
		(start 334.785716 -273.730974)
		(mid 334.636128 -273.854627)
		(end 334.46593 -273.94789)
		(width 0.088646)
		(layer "F.Cu")
		(net "M_A_CPU0_SA_DQ<17>")
	)
	(arc
		(start 333.658464 -274.055332)
		(mid 333.5912 -274.027473)
		(end 333.519018 -274.017994)
		(width 0.088646)
		(layer "F.Cu")
		(net "M_A_CPU0_SA_DQ<17>")
	)
	(segment
		(start 301.967138 -297.616626)
		(end 301.967392 -297.616372)
		(width 0.20066)
		(layer "F.Cu")
		(net "M_A_CPU0_SA_DQ<16>")
	)
	(segment
		(start 304.365152 -297.183556)
		(end 304.37328 -297.191684)
		(width 0.101854)
		(layer "F.Cu")
		(net "M_A_CPU0_SA_DQ<16>")
	)
	(segment
		(start 329.49134 -278.688292)
		(end 328.87158 -281.787854)
		(width 0.1016)
		(layer "F.Cu")
		(net "M_A_CPU0_SA_DQ<16>")
	)
	(segment
		(start 302.21936 -297.86834)
		(end 302.603408 -297.86834)
		(width 0.20066)
		(layer "F.Cu")
		(net "M_A_CPU0_SA_DQ<16>")
	)
	(segment
		(start 311.678066 -297.175682)
		(end 311.107328 -297.36923)
		(width 0.20066)
		(layer "F.Cu")
		(net "M_A_CPU0_SA_DQ<16>")
	)
	(segment
		(start 314.039504 -297.191684)
		(end 311.969404 -297.191684)
		(width 0.1016)
		(layer "F.Cu")
		(net "M_A_CPU0_SA_DQ<16>")
	)
	(segment
		(start 301.967392 -297.616372)
		(end 302.21936 -297.86834)
		(width 0.20066)
		(layer "F.Cu")
		(net "M_A_CPU0_SA_DQ<16>")
	)
	(segment
		(start 303.000156 -297.183556)
		(end 304.319178 -297.183556)
		(width 0.20066)
		(layer "F.Cu")
		(net "M_A_CPU0_SA_DQ<16>")
	)
	(segment
		(start 332.536038 -275.254974)
		(end 329.940412 -277.8506)
		(width 0.1016)
		(layer "F.Cu")
		(net "M_A_CPU0_SA_DQ<16>")
	)
	(segment
		(start 311.969404 -297.191684)
		(end 311.953402 -297.175682)
		(width 0.101854)
		(layer "F.Cu")
		(net "M_A_CPU0_SA_DQ<16>")
	)
	(segment
		(start 328.87158 -293.44747)
		(end 328.535284 -293.783766)
		(width 0.1016)
		(layer "F.Cu")
		(net "M_A_CPU0_SA_DQ<16>")
	)
	(segment
		(start 329.940412 -277.8506)
		(end 329.49134 -278.688292)
		(width 0.1016)
		(layer "F.Cu")
		(net "M_A_CPU0_SA_DQ<16>")
	)
	(segment
		(start 322.634102 -298.233846)
		(end 315.396626 -298.233846)
		(width 0.20066)
		(layer "F.Cu")
		(net "M_A_CPU0_SA_DQ<16>")
	)
	(segment
		(start 315.396626 -298.233846)
		(end 314.337192 -297.174412)
		(width 0.20066)
		(layer "F.Cu")
		(net "M_A_CPU0_SA_DQ<16>")
	)
	(segment
		(start 306.99075 -297.191684)
		(end 307.415692 -297.616626)
		(width 0.20066)
		(layer "F.Cu")
		(net "M_A_CPU0_SA_DQ<16>")
	)
	(segment
		(start 333.375762 -274.54479)
		(end 332.995524 -274.795488)
		(width 0.088646)
		(layer "F.Cu")
		(net "M_A_CPU0_SA_DQ<16>")
	)
	(segment
		(start 304.319178 -297.183556)
		(end 304.365152 -297.183556)
		(width 0.101854)
		(layer "F.Cu")
		(net "M_A_CPU0_SA_DQ<16>")
	)
	(segment
		(start 307.415692 -297.616626)
		(end 308.887114 -297.616626)
		(width 0.20066)
		(layer "F.Cu")
		(net "M_A_CPU0_SA_DQ<16>")
	)
	(segment
		(start 325.11111 -297.20794)
		(end 322.634102 -298.233846)
		(width 0.20066)
		(layer "F.Cu")
		(net "M_A_CPU0_SA_DQ<16>")
	)
	(segment
		(start 302.603408 -297.86834)
		(end 302.837596 -297.634152)
		(width 0.20066)
		(layer "F.Cu")
		(net "M_A_CPU0_SA_DQ<16>")
	)
	(segment
		(start 309.974742 -297.616626)
		(end 308.887114 -297.616626)
		(width 0.20066)
		(layer "F.Cu")
		(net "M_A_CPU0_SA_DQ<16>")
	)
	(segment
		(start 306.60848 -297.191684)
		(end 306.644294 -297.191684)
		(width 0.101854)
		(layer "F.Cu")
		(net "M_A_CPU0_SA_DQ<16>")
	)
	(segment
		(start 314.10148 -297.174412)
		(end 314.056776 -297.174412)
		(width 0.101854)
		(layer "F.Cu")
		(net "M_A_CPU0_SA_DQ<16>")
	)
	(segment
		(start 314.337192 -297.174412)
		(end 314.10148 -297.174412)
		(width 0.20066)
		(layer "F.Cu")
		(net "M_A_CPU0_SA_DQ<16>")
	)
	(segment
		(start 311.107328 -297.36923)
		(end 309.974742 -297.616626)
		(width 0.20066)
		(layer "F.Cu")
		(net "M_A_CPU0_SA_DQ<16>")
	)
	(segment
		(start 302.837596 -297.634152)
		(end 302.837596 -297.346116)
		(width 0.20066)
		(layer "F.Cu")
		(net "M_A_CPU0_SA_DQ<16>")
	)
	(segment
		(start 304.37328 -297.191684)
		(end 306.60848 -297.191684)
		(width 0.1016)
		(layer "F.Cu")
		(net "M_A_CPU0_SA_DQ<16>")
	)
	(segment
		(start 306.644294 -297.191684)
		(end 306.99075 -297.191684)
		(width 0.20066)
		(layer "F.Cu")
		(net "M_A_CPU0_SA_DQ<16>")
	)
	(segment
		(start 301.343314 -297.616626)
		(end 301.967138 -297.616626)
		(width 0.20066)
		(layer "F.Cu")
		(net "M_A_CPU0_SA_DQ<16>")
	)
	(segment
		(start 311.953402 -297.175682)
		(end 311.89168 -297.175682)
		(width 0.101854)
		(layer "F.Cu")
		(net "M_A_CPU0_SA_DQ<16>")
	)
	(segment
		(start 314.056776 -297.174412)
		(end 314.039504 -297.191684)
		(width 0.101854)
		(layer "F.Cu")
		(net "M_A_CPU0_SA_DQ<16>")
	)
	(segment
		(start 328.535284 -293.783766)
		(end 325.11111 -297.20794)
		(width 0.20066)
		(layer "F.Cu")
		(net "M_A_CPU0_SA_DQ<16>")
	)
	(segment
		(start 332.995524 -274.795488)
		(end 332.536038 -275.254974)
		(width 0.088646)
		(layer "F.Cu")
		(net "M_A_CPU0_SA_DQ<16>")
	)
	(segment
		(start 328.87158 -281.787854)
		(end 328.87158 -293.44747)
		(width 0.1016)
		(layer "F.Cu")
		(net "M_A_CPU0_SA_DQ<16>")
	)
	(segment
		(start 302.837596 -297.346116)
		(end 303.000156 -297.183556)
		(width 0.20066)
		(layer "F.Cu")
		(net "M_A_CPU0_SA_DQ<16>")
	)
	(segment
		(start 311.89168 -297.175682)
		(end 311.678066 -297.175682)
		(width 0.20066)
		(layer "F.Cu")
		(net "M_A_CPU0_SA_DQ<16>")
	)
	(segment
		(start 307.782468 -298.911518)
		(end 307.76291 -298.911518)
		(width 0.101854)
		(layer "F.Cu")
		(net "M_A_CPU0_SA_DQ<15>")
	)
	(segment
		(start 310.088026 -298.891706)
		(end 310.03748 -298.891706)
		(width 0.101854)
		(layer "F.Cu")
		(net "M_A_CPU0_SA_DQ<15>")
	)
	(segment
		(start 307.25491 -298.752514)
		(end 307.25491 -298.593002)
		(width 0.20066)
		(layer "F.Cu")
		(net "M_A_CPU0_SA_DQ<15>")
	)
	(segment
		(start 310.639714 -298.891706)
		(end 310.088026 -298.891706)
		(width 0.20066)
		(layer "F.Cu")
		(net "M_A_CPU0_SA_DQ<15>")
	)
	(segment
		(start 311.969658 -298.630848)
		(end 311.462166 -298.630848)
		(width 0.20066)
		(layer "F.Cu")
		(net "M_A_CPU0_SA_DQ<15>")
	)
	(segment
		(start 307.413914 -298.911518)
		(end 307.25491 -298.752514)
		(width 0.20066)
		(layer "F.Cu")
		(net "M_A_CPU0_SA_DQ<15>")
	)
	(segment
		(start 307.76291 -298.911518)
		(end 307.413914 -298.911518)
		(width 0.20066)
		(layer "F.Cu")
		(net "M_A_CPU0_SA_DQ<15>")
	)
	(segment
		(start 311.462166 -298.630848)
		(end 311.252362 -298.421044)
		(width 0.20066)
		(layer "F.Cu")
		(net "M_A_CPU0_SA_DQ<15>")
	)
	(segment
		(start 312.133742 -298.466764)
		(end 311.969658 -298.630848)
		(width 0.20066)
		(layer "F.Cu")
		(net "M_A_CPU0_SA_DQ<15>")
	)
	(segment
		(start 310.769762 -298.761658)
		(end 310.639714 -298.891706)
		(width 0.20066)
		(layer "F.Cu")
		(net "M_A_CPU0_SA_DQ<15>")
	)
	(segment
		(start 307.80228 -298.891706)
		(end 307.782468 -298.911518)
		(width 0.101854)
		(layer "F.Cu")
		(net "M_A_CPU0_SA_DQ<15>")
	)
	(segment
		(start 338.074762 -268.033754)
		(end 338.074762 -268.569694)
		(width 0.20066)
		(layer "F.Cu")
		(net "M_A_CPU0_SA_DQ<15>")
	)
	(segment
		(start 307.25491 -298.593002)
		(end 307.128672 -298.466764)
		(width 0.20066)
		(layer "F.Cu")
		(net "M_A_CPU0_SA_DQ<15>")
	)
	(segment
		(start 310.03748 -298.891706)
		(end 307.80228 -298.891706)
		(width 0.1016)
		(layer "F.Cu")
		(net "M_A_CPU0_SA_DQ<15>")
	)
	(segment
		(start 312.987182 -298.466764)
		(end 312.133742 -298.466764)
		(width 0.20066)
		(layer "F.Cu")
		(net "M_A_CPU0_SA_DQ<15>")
	)
	(segment
		(start 311.252362 -298.421044)
		(end 310.939434 -298.421044)
		(width 0.20066)
		(layer "F.Cu")
		(net "M_A_CPU0_SA_DQ<15>")
	)
	(segment
		(start 310.769762 -298.590716)
		(end 310.769762 -298.761658)
		(width 0.20066)
		(layer "F.Cu")
		(net "M_A_CPU0_SA_DQ<15>")
	)
	(segment
		(start 314.092082 -298.466764)
		(end 312.987182 -298.466764)
		(width 0.20066)
		(layer "F.Cu")
		(net "M_A_CPU0_SA_DQ<15>")
	)
	(segment
		(start 307.128672 -298.466764)
		(end 305.443382 -298.466764)
		(width 0.20066)
		(layer "F.Cu")
		(net "M_A_CPU0_SA_DQ<15>")
	)
	(segment
		(start 310.939434 -298.421044)
		(end 310.769762 -298.590716)
		(width 0.20066)
		(layer "F.Cu")
		(net "M_A_CPU0_SA_DQ<15>")
	)
	(segment
		(start 314.645548 -293.245794)
		(end 314.534296 -293.357046)
		(width 0.18288)
		(layer "In2.Cu")
		(net "M_A_CPU0_SA_DQ<15>")
	)
	(segment
		(start 321.954906 -282.077414)
		(end 317.64986 -286.38246)
		(width 0.18288)
		(layer "In2.Cu")
		(net "M_A_CPU0_SA_DQ<15>")
	)
	(segment
		(start 332.539594 -269.016988)
		(end 328.81443 -272.742152)
		(width 0.18288)
		(layer "In2.Cu")
		(net "M_A_CPU0_SA_DQ<15>")
	)
	(segment
		(start 314.273946 -294.651938)
		(end 312.185304 -294.651938)
		(width 0.18288)
		(layer "In2.Cu")
		(net "M_A_CPU0_SA_DQ<15>")
	)
	(segment
		(start 322.97116 -279.624028)
		(end 321.954906 -282.077414)
		(width 0.18288)
		(layer "In2.Cu")
		(net "M_A_CPU0_SA_DQ<15>")
	)
	(segment
		(start 314.092082 -298.191936)
		(end 314.092082 -298.466764)
		(width 0.18288)
		(layer "In2.Cu")
		(net "M_A_CPU0_SA_DQ<15>")
	)
	(segment
		(start 328.81443 -272.742152)
		(end 328.080116 -274.515072)
		(width 0.18288)
		(layer "In2.Cu")
		(net "M_A_CPU0_SA_DQ<15>")
	)
	(segment
		(start 313.76493 -297.28287)
		(end 312.478166 -297.28287)
		(width 0.18288)
		(layer "In2.Cu")
		(net "M_A_CPU0_SA_DQ<15>")
	)
	(segment
		(start 313.09183 -295.57091)
		(end 313.95797 -296.43705)
		(width 0.18288)
		(layer "In2.Cu")
		(net "M_A_CPU0_SA_DQ<15>")
	)
	(segment
		(start 336.80146 -268.740128)
		(end 336.551524 -268.454378)
		(width 0.088646)
		(layer "In2.Cu")
		(net "M_A_CPU0_SA_DQ<15>")
	)
	(segment
		(start 311.992264 -295.325292)
		(end 312.237882 -295.57091)
		(width 0.18288)
		(layer "In2.Cu")
		(net "M_A_CPU0_SA_DQ<15>")
	)
	(segment
		(start 337.3501 -268.877796)
		(end 337.32216 -268.894052)
		(width 0.088646)
		(layer "In2.Cu")
		(net "M_A_CPU0_SA_DQ<15>")
	)
	(segment
		(start 317.64986 -286.38246)
		(end 314.868306 -293.09695)
		(width 0.18288)
		(layer "In2.Cu")
		(net "M_A_CPU0_SA_DQ<15>")
	)
	(segment
		(start 313.95797 -297.08983)
		(end 313.76493 -297.28287)
		(width 0.18288)
		(layer "In2.Cu")
		(net "M_A_CPU0_SA_DQ<15>")
	)
	(segment
		(start 336.382614 -268.24559)
		(end 336.38236 -268.245336)
		(width 0.088646)
		(layer "In2.Cu")
		(net "M_A_CPU0_SA_DQ<15>")
	)
	(segment
		(start 312.348626 -297.80103)
		(end 312.546492 -297.998896)
		(width 0.18288)
		(layer "In2.Cu")
		(net "M_A_CPU0_SA_DQ<15>")
	)
	(segment
		(start 338.074762 -268.569694)
		(end 337.3501 -268.877796)
		(width 0.088646)
		(layer "In2.Cu")
		(net "M_A_CPU0_SA_DQ<15>")
	)
	(segment
		(start 312.546492 -297.998896)
		(end 313.899042 -297.998896)
		(width 0.18288)
		(layer "In2.Cu")
		(net "M_A_CPU0_SA_DQ<15>")
	)
	(segment
		(start 311.992264 -294.844978)
		(end 311.992264 -295.325292)
		(width 0.18288)
		(layer "In2.Cu")
		(net "M_A_CPU0_SA_DQ<15>")
	)
	(segment
		(start 313.95797 -296.43705)
		(end 313.95797 -297.08983)
		(width 0.18288)
		(layer "In2.Cu")
		(net "M_A_CPU0_SA_DQ<15>")
	)
	(segment
		(start 313.899042 -297.998896)
		(end 314.092082 -298.191936)
		(width 0.18288)
		(layer "In2.Cu")
		(net "M_A_CPU0_SA_DQ<15>")
	)
	(segment
		(start 333.460344 -268.913356)
		(end 332.643226 -268.913356)
		(width 0.088646)
		(layer "In2.Cu")
		(net "M_A_CPU0_SA_DQ<15>")
	)
	(segment
		(start 328.080116 -274.515072)
		(end 322.97116 -279.624028)
		(width 0.18288)
		(layer "In2.Cu")
		(net "M_A_CPU0_SA_DQ<15>")
	)
	(segment
		(start 336.947764 -268.894052)
		(end 336.94751 -268.893798)
		(width 0.088646)
		(layer "In2.Cu")
		(net "M_A_CPU0_SA_DQ<15>")
	)
	(segment
		(start 314.534296 -294.391588)
		(end 314.273946 -294.651938)
		(width 0.18288)
		(layer "In2.Cu")
		(net "M_A_CPU0_SA_DQ<15>")
	)
	(segment
		(start 314.534296 -293.357046)
		(end 314.534296 -294.391588)
		(width 0.18288)
		(layer "In2.Cu")
		(net "M_A_CPU0_SA_DQ<15>")
	)
	(segment
		(start 312.237882 -295.57091)
		(end 313.09183 -295.57091)
		(width 0.18288)
		(layer "In2.Cu")
		(net "M_A_CPU0_SA_DQ<15>")
	)
	(segment
		(start 312.185304 -294.651938)
		(end 311.992264 -294.844978)
		(width 0.18288)
		(layer "In2.Cu")
		(net "M_A_CPU0_SA_DQ<15>")
	)
	(segment
		(start 334.128364 -268.245336)
		(end 333.460344 -268.913356)
		(width 0.088646)
		(layer "In2.Cu")
		(net "M_A_CPU0_SA_DQ<15>")
	)
	(segment
		(start 314.868306 -293.09695)
		(end 314.645548 -293.245794)
		(width 0.18288)
		(layer "In2.Cu")
		(net "M_A_CPU0_SA_DQ<15>")
	)
	(segment
		(start 312.478166 -297.28287)
		(end 312.348626 -297.41241)
		(width 0.18288)
		(layer "In2.Cu")
		(net "M_A_CPU0_SA_DQ<15>")
	)
	(segment
		(start 312.348626 -297.41241)
		(end 312.348626 -297.80103)
		(width 0.18288)
		(layer "In2.Cu")
		(net "M_A_CPU0_SA_DQ<15>")
	)
	(segment
		(start 332.643226 -268.913356)
		(end 332.539594 -269.016988)
		(width 0.088646)
		(layer "In2.Cu")
		(net "M_A_CPU0_SA_DQ<15>")
	)
	(arc
		(start 335.068164 -268.245336)
		(mid 334.785462 -268.321112)
		(end 334.50276 -268.245336)
		(width 0.088646)
		(layer "In2.Cu")
		(net "M_A_CPU0_SA_DQ<15>")
	)
	(arc
		(start 335.44256 -268.245336)
		(mid 335.255362 -268.195193)
		(end 335.068164 -268.245336)
		(width 0.088646)
		(layer "In2.Cu")
		(net "M_A_CPU0_SA_DQ<15>")
	)
	(arc
		(start 336.551524 -268.454378)
		(mid 336.486422 -268.334337)
		(end 336.382614 -268.24559)
		(width 0.088646)
		(layer "In2.Cu")
		(net "M_A_CPU0_SA_DQ<15>")
	)
	(arc
		(start 337.32216 -268.894052)
		(mid 337.134962 -268.944229)
		(end 336.947764 -268.894052)
		(width 0.088646)
		(layer "In2.Cu")
		(net "M_A_CPU0_SA_DQ<15>")
	)
	(arc
		(start 334.50276 -268.245336)
		(mid 334.315562 -268.195193)
		(end 334.128364 -268.245336)
		(width 0.088646)
		(layer "In2.Cu")
		(net "M_A_CPU0_SA_DQ<15>")
	)
	(arc
		(start 336.007964 -268.245336)
		(mid 335.725262 -268.321112)
		(end 335.44256 -268.245336)
		(width 0.088646)
		(layer "In2.Cu")
		(net "M_A_CPU0_SA_DQ<15>")
	)
	(arc
		(start 336.94751 -268.893798)
		(mid 336.86334 -268.827548)
		(end 336.80146 -268.740128)
		(width 0.088646)
		(layer "In2.Cu")
		(net "M_A_CPU0_SA_DQ<15>")
	)
	(arc
		(start 336.38236 -268.245336)
		(mid 336.195162 -268.195193)
		(end 336.007964 -268.245336)
		(width 0.088646)
		(layer "In2.Cu")
		(net "M_A_CPU0_SA_DQ<15>")
	)
	(segment
		(start 307.82768 -299.74159)
		(end 307.811424 -299.725334)
		(width 0.101854)
		(layer "F.Cu")
		(net "M_A_CPU0_SA_DQ<14>")
	)
	(segment
		(start 307.811424 -299.725334)
		(end 307.76291 -299.725334)
		(width 0.101854)
		(layer "F.Cu")
		(net "M_A_CPU0_SA_DQ<14>")
	)
	(segment
		(start 307.04282 -300.039786)
		(end 306.91582 -300.166786)
		(width 0.20066)
		(layer "F.Cu")
		(net "M_A_CPU0_SA_DQ<14>")
	)
	(segment
		(start 306.91582 -300.166786)
		(end 305.443382 -300.166786)
		(width 0.20066)
		(layer "F.Cu")
		(net "M_A_CPU0_SA_DQ<14>")
	)
	(segment
		(start 310.853074 -299.91685)
		(end 310.677814 -299.74159)
		(width 0.20066)
		(layer "F.Cu")
		(net "M_A_CPU0_SA_DQ<14>")
	)
	(segment
		(start 311.339484 -300.345094)
		(end 311.065926 -300.345094)
		(width 0.20066)
		(layer "F.Cu")
		(net "M_A_CPU0_SA_DQ<14>")
	)
	(segment
		(start 312.987182 -300.166786)
		(end 311.517792 -300.166786)
		(width 0.20066)
		(layer "F.Cu")
		(net "M_A_CPU0_SA_DQ<14>")
	)
	(segment
		(start 310.677814 -299.74159)
		(end 310.088026 -299.74159)
		(width 0.20066)
		(layer "F.Cu")
		(net "M_A_CPU0_SA_DQ<14>")
	)
	(segment
		(start 307.04282 -299.856906)
		(end 307.04282 -300.039786)
		(width 0.20066)
		(layer "F.Cu")
		(net "M_A_CPU0_SA_DQ<14>")
	)
	(segment
		(start 311.517792 -300.166786)
		(end 311.339484 -300.345094)
		(width 0.20066)
		(layer "F.Cu")
		(net "M_A_CPU0_SA_DQ<14>")
	)
	(segment
		(start 307.174392 -299.725334)
		(end 307.04282 -299.856906)
		(width 0.20066)
		(layer "F.Cu")
		(net "M_A_CPU0_SA_DQ<14>")
	)
	(segment
		(start 310.088026 -299.74159)
		(end 310.076342 -299.74159)
		(width 0.101854)
		(layer "F.Cu")
		(net "M_A_CPU0_SA_DQ<14>")
	)
	(segment
		(start 310.076342 -299.74159)
		(end 307.82768 -299.74159)
		(width 0.1016)
		(layer "F.Cu")
		(net "M_A_CPU0_SA_DQ<14>")
	)
	(segment
		(start 310.853074 -300.132242)
		(end 310.853074 -299.91685)
		(width 0.20066)
		(layer "F.Cu")
		(net "M_A_CPU0_SA_DQ<14>")
	)
	(segment
		(start 307.76291 -299.725334)
		(end 307.174392 -299.725334)
		(width 0.20066)
		(layer "F.Cu")
		(net "M_A_CPU0_SA_DQ<14>")
	)
	(segment
		(start 338.544662 -268.847824)
		(end 338.544662 -269.38351)
		(width 0.20066)
		(layer "F.Cu")
		(net "M_A_CPU0_SA_DQ<14>")
	)
	(segment
		(start 311.065926 -300.345094)
		(end 310.853074 -300.132242)
		(width 0.20066)
		(layer "F.Cu")
		(net "M_A_CPU0_SA_DQ<14>")
	)
	(segment
		(start 338.544916 -268.84757)
		(end 338.544662 -268.847824)
		(width 0.20066)
		(layer "F.Cu")
		(net "M_A_CPU0_SA_DQ<14>")
	)
	(segment
		(start 314.092082 -300.166786)
		(end 312.987182 -300.166786)
		(width 0.20066)
		(layer "F.Cu")
		(net "M_A_CPU0_SA_DQ<14>")
	)
	(segment
		(start 314.600336 -299.658532)
		(end 314.092082 -300.166786)
		(width 0.18288)
		(layer "In2.Cu")
		(net "M_A_CPU0_SA_DQ<14>")
	)
	(segment
		(start 316.115192 -291.995098)
		(end 315.86297 -292.099746)
		(width 0.18288)
		(layer "In2.Cu")
		(net "M_A_CPU0_SA_DQ<14>")
	)
	(segment
		(start 315.634116 -294.290242)
		(end 315.512196 -294.58412)
		(width 0.18288)
		(layer "In2.Cu")
		(net "M_A_CPU0_SA_DQ<14>")
	)
	(segment
		(start 315.260228 -294.688514)
		(end 315.157358 -294.645842)
		(width 0.18288)
		(layer "In2.Cu")
		(net "M_A_CPU0_SA_DQ<14>")
	)
	(segment
		(start 318.133984 -286.618426)
		(end 317.897002 -287.19145)
		(width 0.18288)
		(layer "In2.Cu")
		(net "M_A_CPU0_SA_DQ<14>")
	)
	(segment
		(start 315.529976 -294.038528)
		(end 315.634116 -294.290242)
		(width 0.18288)
		(layer "In2.Cu")
		(net "M_A_CPU0_SA_DQ<14>")
	)
	(segment
		(start 318.00165 -287.443418)
		(end 318.224916 -287.536128)
		(width 0.18288)
		(layer "In2.Cu")
		(net "M_A_CPU0_SA_DQ<14>")
	)
	(segment
		(start 323.401944 -279.912064)
		(end 322.38569 -282.365196)
		(width 0.18288)
		(layer "In2.Cu")
		(net "M_A_CPU0_SA_DQ<14>")
	)
	(segment
		(start 333.546958 -269.76705)
		(end 333.224378 -269.44447)
		(width 0.088646)
		(layer "In2.Cu")
		(net "M_A_CPU0_SA_DQ<14>")
	)
	(segment
		(start 316.173104 -292.989762)
		(end 316.051184 -293.28364)
		(width 0.18288)
		(layer "In2.Cu")
		(net "M_A_CPU0_SA_DQ<14>")
	)
	(segment
		(start 315.576204 -293.295578)
		(end 315.323982 -293.400226)
		(width 0.18288)
		(layer "In2.Cu")
		(net "M_A_CPU0_SA_DQ<14>")
	)
	(segment
		(start 316.384686 -291.344858)
		(end 316.607952 -291.437568)
		(width 0.18288)
		(layer "In2.Cu")
		(net "M_A_CPU0_SA_DQ<14>")
	)
	(segment
		(start 337.82 -269.075408)
		(end 337.79206 -269.059152)
		(width 0.088646)
		(layer "In2.Cu")
		(net "M_A_CPU0_SA_DQ<14>")
	)
	(segment
		(start 322.38569 -282.365196)
		(end 318.132968 -286.617918)
		(width 0.18288)
		(layer "In2.Cu")
		(net "M_A_CPU0_SA_DQ<14>")
	)
	(segment
		(start 316.877192 -290.787074)
		(end 316.65418 -290.694618)
		(width 0.18288)
		(layer "In2.Cu")
		(net "M_A_CPU0_SA_DQ<14>")
	)
	(segment
		(start 315.86297 -292.099746)
		(end 315.74105 -292.39337)
		(width 0.18288)
		(layer "In2.Cu")
		(net "M_A_CPU0_SA_DQ<14>")
	)
	(segment
		(start 316.338204 -292.087554)
		(end 316.115192 -291.995098)
		(width 0.18288)
		(layer "In2.Cu")
		(net "M_A_CPU0_SA_DQ<14>")
	)
	(segment
		(start 315.323982 -293.400226)
		(end 315.202062 -293.69385)
		(width 0.18288)
		(layer "In2.Cu")
		(net "M_A_CPU0_SA_DQ<14>")
	)
	(segment
		(start 317.25108 -290.388802)
		(end 317.12916 -290.68268)
		(width 0.18288)
		(layer "In2.Cu")
		(net "M_A_CPU0_SA_DQ<14>")
	)
	(segment
		(start 317.14694 -290.137088)
		(end 317.25108 -290.388802)
		(width 0.18288)
		(layer "In2.Cu")
		(net "M_A_CPU0_SA_DQ<14>")
	)
	(segment
		(start 334.220312 -269.373604)
		(end 334.220312 -269.38351)
		(width 0.088646)
		(layer "In2.Cu")
		(net "M_A_CPU0_SA_DQ<14>")
	)
	(segment
		(start 315.799216 -293.388034)
		(end 315.576204 -293.295578)
		(width 0.18288)
		(layer "In2.Cu")
		(net "M_A_CPU0_SA_DQ<14>")
	)
	(segment
		(start 315.202062 -293.69385)
		(end 315.30671 -293.945818)
		(width 0.18288)
		(layer "In2.Cu")
		(net "M_A_CPU0_SA_DQ<14>")
	)
	(segment
		(start 314.894976 -294.7543)
		(end 314.600336 -295.465246)
		(width 0.18288)
		(layer "In2.Cu")
		(net "M_A_CPU0_SA_DQ<14>")
	)
	(segment
		(start 333.831184 -269.76705)
		(end 333.546958 -269.76705)
		(width 0.088646)
		(layer "In2.Cu")
		(net "M_A_CPU0_SA_DQ<14>")
	)
	(segment
		(start 316.940946 -289.498786)
		(end 316.819026 -289.79241)
		(width 0.18288)
		(layer "In2.Cu")
		(net "M_A_CPU0_SA_DQ<14>")
	)
	(segment
		(start 318.132968 -286.617918)
		(end 318.133476 -286.617918)
		(width 0.18288)
		(layer "In2.Cu")
		(net "M_A_CPU0_SA_DQ<14>")
	)
	(segment
		(start 336.477864 -269.059152)
		(end 336.098388 -268.93139)
		(width 0.088646)
		(layer "In2.Cu")
		(net "M_A_CPU0_SA_DQ<14>")
	)
	(segment
		(start 334.04175 -269.702788)
		(end 333.986378 -269.734538)
		(width 0.088646)
		(layer "In2.Cu")
		(net "M_A_CPU0_SA_DQ<14>")
	)
	(segment
		(start 317.955168 -288.186114)
		(end 317.732156 -288.093658)
		(width 0.18288)
		(layer "In2.Cu")
		(net "M_A_CPU0_SA_DQ<14>")
	)
	(segment
		(start 315.30671 -293.945818)
		(end 315.529976 -294.038528)
		(width 0.18288)
		(layer "In2.Cu")
		(net "M_A_CPU0_SA_DQ<14>")
	)
	(segment
		(start 316.607952 -291.437568)
		(end 316.712092 -291.689282)
		(width 0.18288)
		(layer "In2.Cu")
		(net "M_A_CPU0_SA_DQ<14>")
	)
	(segment
		(start 338.544662 -269.38351)
		(end 337.82 -269.075408)
		(width 0.088646)
		(layer "In2.Cu")
		(net "M_A_CPU0_SA_DQ<14>")
	)
	(segment
		(start 317.790068 -289.088322)
		(end 317.668148 -289.3822)
		(width 0.18288)
		(layer "In2.Cu")
		(net "M_A_CPU0_SA_DQ<14>")
	)
	(segment
		(start 328.210418 -275.10359)
		(end 323.401944 -279.912064)
		(width 0.18288)
		(layer "In2.Cu")
		(net "M_A_CPU0_SA_DQ<14>")
	)
	(segment
		(start 332.600808 -269.44447)
		(end 329.108562 -272.936716)
		(width 0.18288)
		(layer "In2.Cu")
		(net "M_A_CPU0_SA_DQ<14>")
	)
	(segment
		(start 314.600336 -295.465246)
		(end 314.600336 -299.658532)
		(width 0.18288)
		(layer "In2.Cu")
		(net "M_A_CPU0_SA_DQ<14>")
	)
	(segment
		(start 315.512196 -294.58412)
		(end 315.260228 -294.688514)
		(width 0.18288)
		(layer "In2.Cu")
		(net "M_A_CPU0_SA_DQ<14>")
	)
	(segment
		(start 317.668148 -289.3822)
		(end 317.41618 -289.486594)
		(width 0.18288)
		(layer "In2.Cu")
		(net "M_A_CPU0_SA_DQ<14>")
	)
	(segment
		(start 316.923674 -290.044378)
		(end 317.14694 -290.137088)
		(width 0.18288)
		(layer "In2.Cu")
		(net "M_A_CPU0_SA_DQ<14>")
	)
	(segment
		(start 317.193168 -289.394138)
		(end 316.940946 -289.498786)
		(width 0.18288)
		(layer "In2.Cu")
		(net "M_A_CPU0_SA_DQ<14>")
	)
	(segment
		(start 316.051184 -293.28364)
		(end 315.799216 -293.388034)
		(width 0.18288)
		(layer "In2.Cu")
		(net "M_A_CPU0_SA_DQ<14>")
	)
	(segment
		(start 316.280038 -291.09289)
		(end 316.384686 -291.344858)
		(width 0.18288)
		(layer "In2.Cu")
		(net "M_A_CPU0_SA_DQ<14>")
	)
	(segment
		(start 316.712092 -291.689282)
		(end 316.590172 -291.98316)
		(width 0.18288)
		(layer "In2.Cu")
		(net "M_A_CPU0_SA_DQ<14>")
	)
	(segment
		(start 315.157358 -294.645842)
		(end 314.894976 -294.7543)
		(width 0.18288)
		(layer "In2.Cu")
		(net "M_A_CPU0_SA_DQ<14>")
	)
	(segment
		(start 318.329056 -287.787842)
		(end 318.207136 -288.08172)
		(width 0.18288)
		(layer "In2.Cu")
		(net "M_A_CPU0_SA_DQ<14>")
	)
	(segment
		(start 318.133476 -286.617918)
		(end 318.133984 -286.618426)
		(width 0.18288)
		(layer "In2.Cu")
		(net "M_A_CPU0_SA_DQ<14>")
	)
	(segment
		(start 317.12916 -290.68268)
		(end 316.877192 -290.787074)
		(width 0.18288)
		(layer "In2.Cu")
		(net "M_A_CPU0_SA_DQ<14>")
	)
	(segment
		(start 317.479934 -288.198306)
		(end 317.358014 -288.49193)
		(width 0.18288)
		(layer "In2.Cu")
		(net "M_A_CPU0_SA_DQ<14>")
	)
	(segment
		(start 329.108562 -272.936716)
		(end 328.210418 -275.10359)
		(width 0.18288)
		(layer "In2.Cu")
		(net "M_A_CPU0_SA_DQ<14>")
	)
	(segment
		(start 316.65418 -290.694618)
		(end 316.401958 -290.799266)
		(width 0.18288)
		(layer "In2.Cu")
		(net "M_A_CPU0_SA_DQ<14>")
	)
	(segment
		(start 315.74105 -292.39337)
		(end 315.845698 -292.645338)
		(width 0.18288)
		(layer "In2.Cu")
		(net "M_A_CPU0_SA_DQ<14>")
	)
	(segment
		(start 317.732156 -288.093658)
		(end 317.479934 -288.198306)
		(width 0.18288)
		(layer "In2.Cu")
		(net "M_A_CPU0_SA_DQ<14>")
	)
	(segment
		(start 315.845698 -292.645338)
		(end 316.068964 -292.738048)
		(width 0.18288)
		(layer "In2.Cu")
		(net "M_A_CPU0_SA_DQ<14>")
	)
	(segment
		(start 317.462662 -288.743898)
		(end 317.685928 -288.836608)
		(width 0.18288)
		(layer "In2.Cu")
		(net "M_A_CPU0_SA_DQ<14>")
	)
	(segment
		(start 317.358014 -288.49193)
		(end 317.462662 -288.743898)
		(width 0.18288)
		(layer "In2.Cu")
		(net "M_A_CPU0_SA_DQ<14>")
	)
	(segment
		(start 316.401958 -290.799266)
		(end 316.280038 -291.09289)
		(width 0.18288)
		(layer "In2.Cu")
		(net "M_A_CPU0_SA_DQ<14>")
	)
	(segment
		(start 316.590172 -291.98316)
		(end 316.338204 -292.087554)
		(width 0.18288)
		(layer "In2.Cu")
		(net "M_A_CPU0_SA_DQ<14>")
	)
	(segment
		(start 317.685928 -288.836608)
		(end 317.790068 -289.088322)
		(width 0.18288)
		(layer "In2.Cu")
		(net "M_A_CPU0_SA_DQ<14>")
	)
	(segment
		(start 332.815946 -269.44447)
		(end 332.600808 -269.44447)
		(width 0.18288)
		(layer "In2.Cu")
		(net "M_A_CPU0_SA_DQ<14>")
	)
	(segment
		(start 318.224916 -287.536128)
		(end 318.329056 -287.787842)
		(width 0.18288)
		(layer "In2.Cu")
		(net "M_A_CPU0_SA_DQ<14>")
	)
	(segment
		(start 317.41618 -289.486594)
		(end 317.193168 -289.394138)
		(width 0.18288)
		(layer "In2.Cu")
		(net "M_A_CPU0_SA_DQ<14>")
	)
	(segment
		(start 318.207136 -288.08172)
		(end 317.955168 -288.186114)
		(width 0.18288)
		(layer "In2.Cu")
		(net "M_A_CPU0_SA_DQ<14>")
	)
	(segment
		(start 317.897002 -287.19145)
		(end 318.00165 -287.443418)
		(width 0.18288)
		(layer "In2.Cu")
		(net "M_A_CPU0_SA_DQ<14>")
	)
	(segment
		(start 316.068964 -292.738048)
		(end 316.173104 -292.989762)
		(width 0.18288)
		(layer "In2.Cu")
		(net "M_A_CPU0_SA_DQ<14>")
	)
	(segment
		(start 333.224378 -269.44447)
		(end 332.815946 -269.44447)
		(width 0.088646)
		(layer "In2.Cu")
		(net "M_A_CPU0_SA_DQ<14>")
	)
	(segment
		(start 316.819026 -289.79241)
		(end 316.923674 -290.044378)
		(width 0.18288)
		(layer "In2.Cu")
		(net "M_A_CPU0_SA_DQ<14>")
	)
	(arc
		(start 335.068164 -268.894052)
		(mid 334.785462 -268.818276)
		(end 334.50276 -268.894052)
		(width 0.088646)
		(layer "In2.Cu")
		(net "M_A_CPU0_SA_DQ<14>")
	)
	(arc
		(start 336.098388 -268.93139)
		(mid 336.051956 -268.915678)
		(end 336.007964 -268.894052)
		(width 0.088646)
		(layer "In2.Cu")
		(net "M_A_CPU0_SA_DQ<14>")
	)
	(arc
		(start 337.79206 -269.059152)
		(mid 337.604862 -269.009009)
		(end 337.417664 -269.059152)
		(width 0.088646)
		(layer "In2.Cu")
		(net "M_A_CPU0_SA_DQ<14>")
	)
	(arc
		(start 336.007964 -268.894052)
		(mid 335.725262 -268.818276)
		(end 335.44256 -268.894052)
		(width 0.088646)
		(layer "In2.Cu")
		(net "M_A_CPU0_SA_DQ<14>")
	)
	(arc
		(start 337.417664 -269.059152)
		(mid 337.134962 -269.134894)
		(end 336.85226 -269.059152)
		(width 0.088646)
		(layer "In2.Cu")
		(net "M_A_CPU0_SA_DQ<14>")
	)
	(arc
		(start 334.220312 -269.38351)
		(mid 334.172633 -269.56641)
		(end 334.04175 -269.702788)
		(width 0.088646)
		(layer "In2.Cu")
		(net "M_A_CPU0_SA_DQ<14>")
	)
	(arc
		(start 334.50276 -268.894052)
		(mid 334.298425 -269.096657)
		(end 334.220312 -269.373604)
		(width 0.088646)
		(layer "In2.Cu")
		(net "M_A_CPU0_SA_DQ<14>")
	)
	(arc
		(start 335.44256 -268.894052)
		(mid 335.255362 -268.944195)
		(end 335.068164 -268.894052)
		(width 0.088646)
		(layer "In2.Cu")
		(net "M_A_CPU0_SA_DQ<14>")
	)
	(arc
		(start 333.986378 -269.734538)
		(mid 333.911339 -269.763009)
		(end 333.831184 -269.76705)
		(width 0.088646)
		(layer "In2.Cu")
		(net "M_A_CPU0_SA_DQ<14>")
	)
	(arc
		(start 336.85226 -269.059152)
		(mid 336.665062 -269.008975)
		(end 336.477864 -269.059152)
		(width 0.088646)
		(layer "In2.Cu")
		(net "M_A_CPU0_SA_DQ<14>")
	)
	(segment
		(start 301.967138 -299.316648)
		(end 301.343314 -299.316648)
		(width 0.20066)
		(layer "F.Cu")
		(net "M_A_CPU0_SA_DQ<13>")
	)
	(segment
		(start 301.967392 -299.316394)
		(end 301.967138 -299.316648)
		(width 0.20066)
		(layer "F.Cu")
		(net "M_A_CPU0_SA_DQ<13>")
	)
	(segment
		(start 302.837596 -299.334174)
		(end 302.603408 -299.568362)
		(width 0.20066)
		(layer "F.Cu")
		(net "M_A_CPU0_SA_DQ<13>")
	)
	(segment
		(start 306.644294 -298.891706)
		(end 306.58308 -298.891706)
		(width 0.101854)
		(layer "F.Cu")
		(net "M_A_CPU0_SA_DQ<13>")
	)
	(segment
		(start 309.992014 -299.316648)
		(end 308.887114 -299.316648)
		(width 0.20066)
		(layer "F.Cu")
		(net "M_A_CPU0_SA_DQ<13>")
	)
	(segment
		(start 306.78882 -298.891706)
		(end 306.644294 -298.891706)
		(width 0.20066)
		(layer "F.Cu")
		(net "M_A_CPU0_SA_DQ<13>")
	)
	(segment
		(start 337.134962 -268.033754)
		(end 337.134962 -268.569694)
		(width 0.20066)
		(layer "F.Cu")
		(net "M_A_CPU0_SA_DQ<13>")
	)
	(segment
		(start 304.319178 -298.870878)
		(end 303.012856 -298.870878)
		(width 0.20066)
		(layer "F.Cu")
		(net "M_A_CPU0_SA_DQ<13>")
	)
	(segment
		(start 308.887114 -299.316648)
		(end 307.213762 -299.316648)
		(width 0.20066)
		(layer "F.Cu")
		(net "M_A_CPU0_SA_DQ<13>")
	)
	(segment
		(start 302.837596 -299.046138)
		(end 302.837596 -299.334174)
		(width 0.20066)
		(layer "F.Cu")
		(net "M_A_CPU0_SA_DQ<13>")
	)
	(segment
		(start 304.37328 -298.891706)
		(end 304.342038 -298.891706)
		(width 0.101854)
		(layer "F.Cu")
		(net "M_A_CPU0_SA_DQ<13>")
	)
	(segment
		(start 303.012856 -298.870878)
		(end 302.837596 -299.046138)
		(width 0.20066)
		(layer "F.Cu")
		(net "M_A_CPU0_SA_DQ<13>")
	)
	(segment
		(start 302.603408 -299.568362)
		(end 302.21936 -299.568362)
		(width 0.20066)
		(layer "F.Cu")
		(net "M_A_CPU0_SA_DQ<13>")
	)
	(segment
		(start 304.32121 -298.870878)
		(end 304.319178 -298.870878)
		(width 0.101854)
		(layer "F.Cu")
		(net "M_A_CPU0_SA_DQ<13>")
	)
	(segment
		(start 302.21936 -299.568362)
		(end 301.967392 -299.316394)
		(width 0.20066)
		(layer "F.Cu")
		(net "M_A_CPU0_SA_DQ<13>")
	)
	(segment
		(start 306.58308 -298.891706)
		(end 304.37328 -298.891706)
		(width 0.1016)
		(layer "F.Cu")
		(net "M_A_CPU0_SA_DQ<13>")
	)
	(segment
		(start 304.342038 -298.891706)
		(end 304.32121 -298.870878)
		(width 0.101854)
		(layer "F.Cu")
		(net "M_A_CPU0_SA_DQ<13>")
	)
	(segment
		(start 307.213762 -299.316648)
		(end 306.78882 -298.891706)
		(width 0.20066)
		(layer "F.Cu")
		(net "M_A_CPU0_SA_DQ<13>")
	)
	(segment
		(start 311.551066 -297.036744)
		(end 311.358026 -297.229784)
		(width 0.18288)
		(layer "In2.Cu")
		(net "M_A_CPU0_SA_DQ<13>")
	)
	(segment
		(start 310.143906 -297.852846)
		(end 310.526176 -298.235116)
		(width 0.18288)
		(layer "In2.Cu")
		(net "M_A_CPU0_SA_DQ<13>")
	)
	(segment
		(start 333.462122 -268.600682)
		(end 332.467204 -268.600682)
		(width 0.088646)
		(layer "In2.Cu")
		(net "M_A_CPU0_SA_DQ<13>")
	)
	(segment
		(start 314.460636 -292.618414)
		(end 314.008008 -293.071042)
		(width 0.18288)
		(layer "In2.Cu")
		(net "M_A_CPU0_SA_DQ<13>")
	)
	(segment
		(start 311.358026 -297.229784)
		(end 310.336946 -297.229784)
		(width 0.18288)
		(layer "In2.Cu")
		(net "M_A_CPU0_SA_DQ<13>")
	)
	(segment
		(start 313.814968 -293.784782)
		(end 311.588912 -293.784782)
		(width 0.18288)
		(layer "In2.Cu")
		(net "M_A_CPU0_SA_DQ<13>")
	)
	(segment
		(start 310.352186 -295.594532)
		(end 310.159146 -295.787572)
		(width 0.18288)
		(layer "In2.Cu")
		(net "M_A_CPU0_SA_DQ<13>")
	)
	(segment
		(start 314.008008 -293.591742)
		(end 313.814968 -293.784782)
		(width 0.18288)
		(layer "In2.Cu")
		(net "M_A_CPU0_SA_DQ<13>")
	)
	(segment
		(start 314.008008 -293.071042)
		(end 314.008008 -293.591742)
		(width 0.18288)
		(layer "In2.Cu")
		(net "M_A_CPU0_SA_DQ<13>")
	)
	(segment
		(start 310.159146 -296.105072)
		(end 310.352186 -296.298112)
		(width 0.18288)
		(layer "In2.Cu")
		(net "M_A_CPU0_SA_DQ<13>")
	)
	(segment
		(start 310.526176 -298.235116)
		(end 310.526176 -298.798742)
		(width 0.18288)
		(layer "In2.Cu")
		(net "M_A_CPU0_SA_DQ<13>")
	)
	(segment
		(start 310.00827 -299.316648)
		(end 309.992014 -299.316648)
		(width 0.18288)
		(layer "In2.Cu")
		(net "M_A_CPU0_SA_DQ<13>")
	)
	(segment
		(start 337.134962 -268.569694)
		(end 336.506058 -268.096492)
		(width 0.088646)
		(layer "In2.Cu")
		(net "M_A_CPU0_SA_DQ<13>")
	)
	(segment
		(start 333.817468 -268.245336)
		(end 333.462122 -268.600682)
		(width 0.088646)
		(layer "In2.Cu")
		(net "M_A_CPU0_SA_DQ<13>")
	)
	(segment
		(start 311.588912 -293.784782)
		(end 311.395872 -293.977822)
		(width 0.18288)
		(layer "In2.Cu")
		(net "M_A_CPU0_SA_DQ<13>")
	)
	(segment
		(start 332.467204 -268.600682)
		(end 332.295246 -268.77264)
		(width 0.088646)
		(layer "In2.Cu")
		(net "M_A_CPU0_SA_DQ<13>")
	)
	(segment
		(start 317.122556 -286.190944)
		(end 314.460636 -292.618414)
		(width 0.18288)
		(layer "In2.Cu")
		(net "M_A_CPU0_SA_DQ<13>")
	)
	(segment
		(start 332.295246 -268.77264)
		(end 328.518012 -272.549874)
		(width 0.18288)
		(layer "In2.Cu")
		(net "M_A_CPU0_SA_DQ<13>")
	)
	(segment
		(start 311.358026 -296.298112)
		(end 311.551066 -296.491152)
		(width 0.18288)
		(layer "In2.Cu")
		(net "M_A_CPU0_SA_DQ<13>")
	)
	(segment
		(start 310.159146 -295.787572)
		(end 310.159146 -296.105072)
		(width 0.18288)
		(layer "In2.Cu")
		(net "M_A_CPU0_SA_DQ<13>")
	)
	(segment
		(start 310.526176 -298.798742)
		(end 310.00827 -299.316648)
		(width 0.18288)
		(layer "In2.Cu")
		(net "M_A_CPU0_SA_DQ<13>")
	)
	(segment
		(start 310.352186 -296.298112)
		(end 311.358026 -296.298112)
		(width 0.18288)
		(layer "In2.Cu")
		(net "M_A_CPU0_SA_DQ<13>")
	)
	(segment
		(start 311.395872 -295.401492)
		(end 311.202832 -295.594532)
		(width 0.18288)
		(layer "In2.Cu")
		(net "M_A_CPU0_SA_DQ<13>")
	)
	(segment
		(start 311.551066 -296.491152)
		(end 311.551066 -297.036744)
		(width 0.18288)
		(layer "In2.Cu")
		(net "M_A_CPU0_SA_DQ<13>")
	)
	(segment
		(start 328.518012 -272.549874)
		(end 327.946258 -273.93011)
		(width 0.18288)
		(layer "In2.Cu")
		(net "M_A_CPU0_SA_DQ<13>")
	)
	(segment
		(start 322.54063 -279.335738)
		(end 321.524376 -281.789124)
		(width 0.18288)
		(layer "In2.Cu")
		(net "M_A_CPU0_SA_DQ<13>")
	)
	(segment
		(start 311.202832 -295.594532)
		(end 310.352186 -295.594532)
		(width 0.18288)
		(layer "In2.Cu")
		(net "M_A_CPU0_SA_DQ<13>")
	)
	(segment
		(start 327.946258 -273.93011)
		(end 322.54063 -279.335738)
		(width 0.18288)
		(layer "In2.Cu")
		(net "M_A_CPU0_SA_DQ<13>")
	)
	(segment
		(start 310.336946 -297.229784)
		(end 310.143906 -297.422824)
		(width 0.18288)
		(layer "In2.Cu")
		(net "M_A_CPU0_SA_DQ<13>")
	)
	(segment
		(start 311.395872 -293.977822)
		(end 311.395872 -295.401492)
		(width 0.18288)
		(layer "In2.Cu")
		(net "M_A_CPU0_SA_DQ<13>")
	)
	(segment
		(start 336.506058 -268.096492)
		(end 336.477864 -268.080236)
		(width 0.088646)
		(layer "In2.Cu")
		(net "M_A_CPU0_SA_DQ<13>")
	)
	(segment
		(start 310.143906 -297.422824)
		(end 310.143906 -297.852846)
		(width 0.18288)
		(layer "In2.Cu")
		(net "M_A_CPU0_SA_DQ<13>")
	)
	(segment
		(start 321.524376 -281.789124)
		(end 317.122556 -286.190944)
		(width 0.18288)
		(layer "In2.Cu")
		(net "M_A_CPU0_SA_DQ<13>")
	)
	(arc
		(start 335.91246 -268.080236)
		(mid 335.725262 -268.130379)
		(end 335.538064 -268.080236)
		(width 0.088646)
		(layer "In2.Cu")
		(net "M_A_CPU0_SA_DQ<13>")
	)
	(arc
		(start 334.03286 -268.080236)
		(mid 333.919745 -268.155715)
		(end 333.817468 -268.245336)
		(width 0.088646)
		(layer "In2.Cu")
		(net "M_A_CPU0_SA_DQ<13>")
	)
	(arc
		(start 335.538064 -268.080236)
		(mid 335.255362 -268.00446)
		(end 334.97266 -268.080236)
		(width 0.088646)
		(layer "In2.Cu")
		(net "M_A_CPU0_SA_DQ<13>")
	)
	(arc
		(start 336.477864 -268.080236)
		(mid 336.195162 -268.004494)
		(end 335.91246 -268.080236)
		(width 0.088646)
		(layer "In2.Cu")
		(net "M_A_CPU0_SA_DQ<13>")
	)
	(arc
		(start 334.598264 -268.080236)
		(mid 334.315562 -268.00446)
		(end 334.03286 -268.080236)
		(width 0.088646)
		(layer "In2.Cu")
		(net "M_A_CPU0_SA_DQ<13>")
	)
	(arc
		(start 334.97266 -268.080236)
		(mid 334.785462 -268.130379)
		(end 334.598264 -268.080236)
		(width 0.088646)
		(layer "In2.Cu")
		(net "M_A_CPU0_SA_DQ<13>")
	)
	(segment
		(start 307.790596 -300.825408)
		(end 307.077364 -300.825408)
		(width 0.20066)
		(layer "F.Cu")
		(net "M_A_CPU0_SA_DQ<12>")
	)
	(segment
		(start 308.887114 -301.01667)
		(end 307.981858 -301.01667)
		(width 0.20066)
		(layer "F.Cu")
		(net "M_A_CPU0_SA_DQ<12>")
	)
	(segment
		(start 304.352452 -300.5709)
		(end 304.319178 -300.5709)
		(width 0.101854)
		(layer "F.Cu")
		(net "M_A_CPU0_SA_DQ<12>")
	)
	(segment
		(start 336.665062 -268.847824)
		(end 336.665062 -269.38351)
		(width 0.20066)
		(layer "F.Cu")
		(net "M_A_CPU0_SA_DQ<12>")
	)
	(segment
		(start 302.837596 -301.034196)
		(end 302.603408 -301.268384)
		(width 0.20066)
		(layer "F.Cu")
		(net "M_A_CPU0_SA_DQ<12>")
	)
	(segment
		(start 306.644294 -300.591728)
		(end 306.60848 -300.591728)
		(width 0.101854)
		(layer "F.Cu")
		(net "M_A_CPU0_SA_DQ<12>")
	)
	(segment
		(start 306.843684 -300.591728)
		(end 306.644294 -300.591728)
		(width 0.20066)
		(layer "F.Cu")
		(net "M_A_CPU0_SA_DQ<12>")
	)
	(segment
		(start 301.967392 -301.016416)
		(end 301.967138 -301.01667)
		(width 0.20066)
		(layer "F.Cu")
		(net "M_A_CPU0_SA_DQ<12>")
	)
	(segment
		(start 309.992014 -301.01667)
		(end 308.887114 -301.01667)
		(width 0.20066)
		(layer "F.Cu")
		(net "M_A_CPU0_SA_DQ<12>")
	)
	(segment
		(start 304.37328 -300.591728)
		(end 304.352452 -300.5709)
		(width 0.101854)
		(layer "F.Cu")
		(net "M_A_CPU0_SA_DQ<12>")
	)
	(segment
		(start 303.012856 -300.5709)
		(end 302.837596 -300.74616)
		(width 0.20066)
		(layer "F.Cu")
		(net "M_A_CPU0_SA_DQ<12>")
	)
	(segment
		(start 302.603408 -301.268384)
		(end 302.21936 -301.268384)
		(width 0.20066)
		(layer "F.Cu")
		(net "M_A_CPU0_SA_DQ<12>")
	)
	(segment
		(start 302.21936 -301.268384)
		(end 301.967392 -301.016416)
		(width 0.20066)
		(layer "F.Cu")
		(net "M_A_CPU0_SA_DQ<12>")
	)
	(segment
		(start 302.837596 -300.74616)
		(end 302.837596 -301.034196)
		(width 0.20066)
		(layer "F.Cu")
		(net "M_A_CPU0_SA_DQ<12>")
	)
	(segment
		(start 307.077364 -300.825408)
		(end 306.843684 -300.591728)
		(width 0.20066)
		(layer "F.Cu")
		(net "M_A_CPU0_SA_DQ<12>")
	)
	(segment
		(start 301.967138 -301.01667)
		(end 301.343314 -301.01667)
		(width 0.20066)
		(layer "F.Cu")
		(net "M_A_CPU0_SA_DQ<12>")
	)
	(segment
		(start 307.981858 -301.01667)
		(end 307.790596 -300.825408)
		(width 0.20066)
		(layer "F.Cu")
		(net "M_A_CPU0_SA_DQ<12>")
	)
	(segment
		(start 304.319178 -300.5709)
		(end 303.012856 -300.5709)
		(width 0.20066)
		(layer "F.Cu")
		(net "M_A_CPU0_SA_DQ<12>")
	)
	(segment
		(start 306.60848 -300.591728)
		(end 304.37328 -300.591728)
		(width 0.1016)
		(layer "F.Cu")
		(net "M_A_CPU0_SA_DQ<12>")
	)
	(segment
		(start 336.665316 -268.84757)
		(end 336.665062 -268.847824)
		(width 0.20066)
		(layer "F.Cu")
		(net "M_A_CPU0_SA_DQ<12>")
	)
	(segment
		(start 315.280802 -295.31437)
		(end 315.108336 -295.731184)
		(width 0.18288)
		(layer "In2.Cu")
		(net "M_A_CPU0_SA_DQ<12>")
	)
	(segment
		(start 323.832474 -280.200354)
		(end 322.81622 -282.653486)
		(width 0.18288)
		(layer "In2.Cu")
		(net "M_A_CPU0_SA_DQ<12>")
	)
	(segment
		(start 314.399168 -300.591728)
		(end 313.223656 -300.591728)
		(width 0.18288)
		(layer "In2.Cu")
		(net "M_A_CPU0_SA_DQ<12>")
	)
	(segment
		(start 311.33415 -301.625762)
		(end 311.14111 -301.818802)
		(width 0.18288)
		(layer "In2.Cu")
		(net "M_A_CPU0_SA_DQ<12>")
	)
	(segment
		(start 310.43753 -301.01667)
		(end 309.992014 -301.01667)
		(width 0.18288)
		(layer "In2.Cu")
		(net "M_A_CPU0_SA_DQ<12>")
	)
	(segment
		(start 311.14111 -301.818802)
		(end 310.82361 -301.818802)
		(width 0.18288)
		(layer "In2.Cu")
		(net "M_A_CPU0_SA_DQ<12>")
	)
	(segment
		(start 334.598264 -269.059152)
		(end 334.589374 -269.064232)
		(width 0.088646)
		(layer "In2.Cu")
		(net "M_A_CPU0_SA_DQ<12>")
	)
	(segment
		(start 314.931552 -300.236128)
		(end 314.399168 -300.591728)
		(width 0.18288)
		(layer "In2.Cu")
		(net "M_A_CPU0_SA_DQ<12>")
	)
	(segment
		(start 312.519822 -301.372016)
		(end 312.326782 -301.178976)
		(width 0.18288)
		(layer "In2.Cu")
		(net "M_A_CPU0_SA_DQ<12>")
	)
	(segment
		(start 335.9404 -269.075408)
		(end 335.91246 -269.059152)
		(width 0.088646)
		(layer "In2.Cu")
		(net "M_A_CPU0_SA_DQ<12>")
	)
	(segment
		(start 312.837322 -301.372016)
		(end 312.519822 -301.372016)
		(width 0.18288)
		(layer "In2.Cu")
		(net "M_A_CPU0_SA_DQ<12>")
	)
	(segment
		(start 312.326782 -300.785022)
		(end 311.953656 -300.411896)
		(width 0.18288)
		(layer "In2.Cu")
		(net "M_A_CPU0_SA_DQ<12>")
	)
	(segment
		(start 329.402694 -273.13128)
		(end 328.34326 -275.689568)
		(width 0.18288)
		(layer "In2.Cu")
		(net "M_A_CPU0_SA_DQ<12>")
	)
	(segment
		(start 333.854552 -269.981426)
		(end 333.286862 -269.981426)
		(width 0.088646)
		(layer "In2.Cu")
		(net "M_A_CPU0_SA_DQ<12>")
	)
	(segment
		(start 315.108336 -299.809408)
		(end 314.931552 -300.236128)
		(width 0.18288)
		(layer "In2.Cu")
		(net "M_A_CPU0_SA_DQ<12>")
	)
	(segment
		(start 310.63057 -301.625762)
		(end 310.63057 -301.20971)
		(width 0.18288)
		(layer "In2.Cu")
		(net "M_A_CPU0_SA_DQ<12>")
	)
	(segment
		(start 313.030362 -300.785022)
		(end 313.030362 -301.178976)
		(width 0.18288)
		(layer "In2.Cu")
		(net "M_A_CPU0_SA_DQ<12>")
	)
	(segment
		(start 313.030362 -301.178976)
		(end 312.837322 -301.372016)
		(width 0.18288)
		(layer "In2.Cu")
		(net "M_A_CPU0_SA_DQ<12>")
	)
	(segment
		(start 336.665062 -269.38351)
		(end 335.9404 -269.075408)
		(width 0.088646)
		(layer "In2.Cu")
		(net "M_A_CPU0_SA_DQ<12>")
	)
	(segment
		(start 328.34326 -275.689568)
		(end 323.832474 -280.200354)
		(width 0.18288)
		(layer "In2.Cu")
		(net "M_A_CPU0_SA_DQ<12>")
	)
	(segment
		(start 334.128364 -269.873222)
		(end 334.016604 -269.937992)
		(width 0.088646)
		(layer "In2.Cu")
		(net "M_A_CPU0_SA_DQ<12>")
	)
	(segment
		(start 322.81622 -282.653486)
		(end 319.72504 -285.744666)
		(width 0.18288)
		(layer "In2.Cu")
		(net "M_A_CPU0_SA_DQ<12>")
	)
	(segment
		(start 315.861954 -295.073578)
		(end 315.280802 -295.31437)
		(width 0.18288)
		(layer "In2.Cu")
		(net "M_A_CPU0_SA_DQ<12>")
	)
	(segment
		(start 319.72504 -285.744666)
		(end 315.861954 -295.073578)
		(width 0.18288)
		(layer "In2.Cu")
		(net "M_A_CPU0_SA_DQ<12>")
	)
	(segment
		(start 311.33415 -300.671484)
		(end 311.33415 -301.625762)
		(width 0.18288)
		(layer "In2.Cu")
		(net "M_A_CPU0_SA_DQ<12>")
	)
	(segment
		(start 310.63057 -301.20971)
		(end 310.43753 -301.01667)
		(width 0.18288)
		(layer "In2.Cu")
		(net "M_A_CPU0_SA_DQ<12>")
	)
	(segment
		(start 311.593738 -300.411896)
		(end 311.33415 -300.671484)
		(width 0.18288)
		(layer "In2.Cu")
		(net "M_A_CPU0_SA_DQ<12>")
	)
	(segment
		(start 315.108336 -295.731184)
		(end 315.108336 -299.809408)
		(width 0.18288)
		(layer "In2.Cu")
		(net "M_A_CPU0_SA_DQ<12>")
	)
	(segment
		(start 332.10627 -270.427704)
		(end 329.402694 -273.13128)
		(width 0.18288)
		(layer "In2.Cu")
		(net "M_A_CPU0_SA_DQ<12>")
	)
	(segment
		(start 312.326782 -301.178976)
		(end 312.326782 -300.785022)
		(width 0.18288)
		(layer "In2.Cu")
		(net "M_A_CPU0_SA_DQ<12>")
	)
	(segment
		(start 311.953656 -300.411896)
		(end 311.593738 -300.411896)
		(width 0.18288)
		(layer "In2.Cu")
		(net "M_A_CPU0_SA_DQ<12>")
	)
	(segment
		(start 313.223656 -300.591728)
		(end 313.030362 -300.785022)
		(width 0.18288)
		(layer "In2.Cu")
		(net "M_A_CPU0_SA_DQ<12>")
	)
	(segment
		(start 332.944978 -270.32331)
		(end 332.210664 -270.32331)
		(width 0.088646)
		(layer "In2.Cu")
		(net "M_A_CPU0_SA_DQ<12>")
	)
	(segment
		(start 333.286862 -269.981426)
		(end 332.944978 -270.32331)
		(width 0.088646)
		(layer "In2.Cu")
		(net "M_A_CPU0_SA_DQ<12>")
	)
	(segment
		(start 310.82361 -301.818802)
		(end 310.63057 -301.625762)
		(width 0.18288)
		(layer "In2.Cu")
		(net "M_A_CPU0_SA_DQ<12>")
	)
	(segment
		(start 332.210664 -270.32331)
		(end 332.10627 -270.427704)
		(width 0.088646)
		(layer "In2.Cu")
		(net "M_A_CPU0_SA_DQ<12>")
	)
	(segment
		(start 334.410812 -269.38351)
		(end 334.410812 -269.402052)
		(width 0.088646)
		(layer "In2.Cu")
		(net "M_A_CPU0_SA_DQ<12>")
	)
	(arc
		(start 335.91246 -269.059152)
		(mid 335.725262 -269.009009)
		(end 335.538064 -269.059152)
		(width 0.088646)
		(layer "In2.Cu")
		(net "M_A_CPU0_SA_DQ<12>")
	)
	(arc
		(start 334.410812 -269.402052)
		(mid 334.33065 -269.674241)
		(end 334.128364 -269.873222)
		(width 0.088646)
		(layer "In2.Cu")
		(net "M_A_CPU0_SA_DQ<12>")
	)
	(arc
		(start 334.589374 -269.064232)
		(mid 334.45846 -269.200592)
		(end 334.410812 -269.38351)
		(width 0.088646)
		(layer "In2.Cu")
		(net "M_A_CPU0_SA_DQ<12>")
	)
	(arc
		(start 334.016604 -269.937992)
		(mid 333.938437 -269.970371)
		(end 333.854552 -269.981426)
		(width 0.088646)
		(layer "In2.Cu")
		(net "M_A_CPU0_SA_DQ<12>")
	)
	(arc
		(start 335.538064 -269.059152)
		(mid 335.255362 -269.134928)
		(end 334.97266 -269.059152)
		(width 0.088646)
		(layer "In2.Cu")
		(net "M_A_CPU0_SA_DQ<12>")
	)
	(arc
		(start 334.97266 -269.059152)
		(mid 334.785462 -269.009009)
		(end 334.598264 -269.059152)
		(width 0.088646)
		(layer "In2.Cu")
		(net "M_A_CPU0_SA_DQ<12>")
	)
	(segment
		(start 310.769762 -304.711608)
		(end 310.639714 -304.841656)
		(width 0.20066)
		(layer "F.Cu")
		(net "M_A_CPU0_SA_DQ<11>")
	)
	(segment
		(start 307.411882 -304.859436)
		(end 307.25491 -304.702464)
		(width 0.20066)
		(layer "F.Cu")
		(net "M_A_CPU0_SA_DQ<11>")
	)
	(segment
		(start 310.939434 -304.370994)
		(end 310.769762 -304.540666)
		(width 0.20066)
		(layer "F.Cu")
		(net "M_A_CPU0_SA_DQ<11>")
	)
	(segment
		(start 307.76291 -304.859436)
		(end 307.411882 -304.859436)
		(width 0.20066)
		(layer "F.Cu")
		(net "M_A_CPU0_SA_DQ<11>")
	)
	(segment
		(start 307.80228 -304.841656)
		(end 307.7845 -304.859436)
		(width 0.101854)
		(layer "F.Cu")
		(net "M_A_CPU0_SA_DQ<11>")
	)
	(segment
		(start 312.987182 -304.416714)
		(end 312.133742 -304.416714)
		(width 0.20066)
		(layer "F.Cu")
		(net "M_A_CPU0_SA_DQ<11>")
	)
	(segment
		(start 310.639714 -304.841656)
		(end 310.088026 -304.841656)
		(width 0.20066)
		(layer "F.Cu")
		(net "M_A_CPU0_SA_DQ<11>")
	)
	(segment
		(start 307.25491 -304.542444)
		(end 307.128926 -304.41646)
		(width 0.20066)
		(layer "F.Cu")
		(net "M_A_CPU0_SA_DQ<11>")
	)
	(segment
		(start 310.03748 -304.841656)
		(end 307.80228 -304.841656)
		(width 0.1016)
		(layer "F.Cu")
		(net "M_A_CPU0_SA_DQ<11>")
	)
	(segment
		(start 311.252362 -304.370994)
		(end 310.939434 -304.370994)
		(width 0.20066)
		(layer "F.Cu")
		(net "M_A_CPU0_SA_DQ<11>")
	)
	(segment
		(start 307.128672 -304.416714)
		(end 305.443382 -304.416714)
		(width 0.20066)
		(layer "F.Cu")
		(net "M_A_CPU0_SA_DQ<11>")
	)
	(segment
		(start 311.95899 -304.591466)
		(end 311.472834 -304.591466)
		(width 0.20066)
		(layer "F.Cu")
		(net "M_A_CPU0_SA_DQ<11>")
	)
	(segment
		(start 307.7845 -304.859436)
		(end 307.76291 -304.859436)
		(width 0.101854)
		(layer "F.Cu")
		(net "M_A_CPU0_SA_DQ<11>")
	)
	(segment
		(start 338.544916 -271.011142)
		(end 338.544662 -271.011396)
		(width 0.20066)
		(layer "F.Cu")
		(net "M_A_CPU0_SA_DQ<11>")
	)
	(segment
		(start 310.088026 -304.841656)
		(end 310.03748 -304.841656)
		(width 0.101854)
		(layer "F.Cu")
		(net "M_A_CPU0_SA_DQ<11>")
	)
	(segment
		(start 312.133742 -304.416714)
		(end 311.95899 -304.591466)
		(width 0.20066)
		(layer "F.Cu")
		(net "M_A_CPU0_SA_DQ<11>")
	)
	(segment
		(start 310.769762 -304.540666)
		(end 310.769762 -304.711608)
		(width 0.20066)
		(layer "F.Cu")
		(net "M_A_CPU0_SA_DQ<11>")
	)
	(segment
		(start 314.092082 -304.416714)
		(end 312.987182 -304.416714)
		(width 0.20066)
		(layer "F.Cu")
		(net "M_A_CPU0_SA_DQ<11>")
	)
	(segment
		(start 338.544916 -270.475456)
		(end 338.544916 -271.011142)
		(width 0.20066)
		(layer "F.Cu")
		(net "M_A_CPU0_SA_DQ<11>")
	)
	(segment
		(start 307.25491 -304.702464)
		(end 307.25491 -304.542444)
		(width 0.20066)
		(layer "F.Cu")
		(net "M_A_CPU0_SA_DQ<11>")
	)
	(segment
		(start 311.472834 -304.591466)
		(end 311.252362 -304.370994)
		(width 0.20066)
		(layer "F.Cu")
		(net "M_A_CPU0_SA_DQ<11>")
	)
	(segment
		(start 307.128926 -304.41646)
		(end 307.128672 -304.416714)
		(width 0.20066)
		(layer "F.Cu")
		(net "M_A_CPU0_SA_DQ<11>")
	)
	(segment
		(start 320.732912 -289.642804)
		(end 320.837052 -289.894518)
		(width 0.18288)
		(layer "In2.Cu")
		(net "M_A_CPU0_SA_DQ<11>")
	)
	(segment
		(start 320.565272 -291.514784)
		(end 320.443352 -291.808408)
		(width 0.18288)
		(layer "In2.Cu")
		(net "M_A_CPU0_SA_DQ<11>")
	)
	(segment
		(start 320.298064 -291.194998)
		(end 320.460878 -291.262562)
		(width 0.18288)
		(layer "In2.Cu")
		(net "M_A_CPU0_SA_DQ<11>")
	)
	(segment
		(start 322.542662 -286.446214)
		(end 322.148962 -286.446214)
		(width 0.18288)
		(layer "In2.Cu")
		(net "M_A_CPU0_SA_DQ<11>")
	)
	(segment
		(start 319.776856 -291.949632)
		(end 319.654936 -292.243764)
		(width 0.18288)
		(layer "In2.Cu")
		(net "M_A_CPU0_SA_DQ<11>")
	)
	(segment
		(start 316.418722 -302.882554)
		(end 314.884562 -304.416714)
		(width 0.18288)
		(layer "In2.Cu")
		(net "M_A_CPU0_SA_DQ<11>")
	)
	(segment
		(start 320.837052 -289.894518)
		(end 321.002406 -289.963098)
		(width 0.18288)
		(layer "In2.Cu")
		(net "M_A_CPU0_SA_DQ<11>")
	)
	(segment
		(start 336.477864 -270.687038)
		(end 336.477864 -270.687292)
		(width 0.088646)
		(layer "In2.Cu")
		(net "M_A_CPU0_SA_DQ<11>")
	)
	(segment
		(start 314.884562 -304.416714)
		(end 314.092082 -304.416714)
		(width 0.18288)
		(layer "In2.Cu")
		(net "M_A_CPU0_SA_DQ<11>")
	)
	(segment
		(start 326.005952 -280.722832)
		(end 325.899272 -280.980642)
		(width 0.18288)
		(layer "In2.Cu")
		(net "M_A_CPU0_SA_DQ<11>")
	)
	(segment
		(start 337.267296 -271.257014)
		(end 337.117182 -270.997172)
		(width 0.088646)
		(layer "In2.Cu")
		(net "M_A_CPU0_SA_DQ<11>")
	)
	(segment
		(start 337.419188 -271.35709)
		(end 337.267296 -271.257014)
		(width 0.088646)
		(layer "In2.Cu")
		(net "M_A_CPU0_SA_DQ<11>")
	)
	(segment
		(start 319.92189 -292.563042)
		(end 320.026284 -292.815264)
		(width 0.18288)
		(layer "In2.Cu")
		(net "M_A_CPU0_SA_DQ<11>")
	)
	(segment
		(start 337.82 -271.319498)
		(end 337.7565 -271.356582)
		(width 0.088646)
		(layer "In2.Cu")
		(net "M_A_CPU0_SA_DQ<11>")
	)
	(segment
		(start 321.271392 -289.312858)
		(end 321.106546 -289.244532)
		(width 0.18288)
		(layer "In2.Cu")
		(net "M_A_CPU0_SA_DQ<11>")
	)
	(segment
		(start 322.148962 -286.446214)
		(end 321.992498 -286.602678)
		(width 0.18288)
		(layer "In2.Cu")
		(net "M_A_CPU0_SA_DQ<11>")
	)
	(segment
		(start 329.70724 -277.021544)
		(end 326.005952 -280.722832)
		(width 0.18288)
		(layer "In2.Cu")
		(net "M_A_CPU0_SA_DQ<11>")
	)
	(segment
		(start 321.39255 -288.047684)
		(end 321.27063 -288.341816)
		(width 0.18288)
		(layer "In2.Cu")
		(net "M_A_CPU0_SA_DQ<11>")
	)
	(segment
		(start 320.193924 -290.943284)
		(end 320.298064 -291.194998)
		(width 0.18288)
		(layer "In2.Cu")
		(net "M_A_CPU0_SA_DQ<11>")
	)
	(segment
		(start 320.854832 -289.348672)
		(end 320.732912 -289.642804)
		(width 0.18288)
		(layer "In2.Cu")
		(net "M_A_CPU0_SA_DQ<11>")
	)
	(segment
		(start 333.292196 -271.613884)
		(end 330.997052 -273.909028)
		(width 0.18288)
		(layer "In2.Cu")
		(net "M_A_CPU0_SA_DQ<11>")
	)
	(segment
		(start 338.544662 -271.011396)
		(end 337.82 -271.319498)
		(width 0.088646)
		(layer "In2.Cu")
		(net "M_A_CPU0_SA_DQ<11>")
	)
	(segment
		(start 335.912714 -271.3355)
		(end 335.91246 -271.335754)
		(width 0.088646)
		(layer "In2.Cu")
		(net "M_A_CPU0_SA_DQ<11>")
	)
	(segment
		(start 320.567558 -290.545012)
		(end 320.315844 -290.649152)
		(width 0.18288)
		(layer "In2.Cu")
		(net "M_A_CPU0_SA_DQ<11>")
	)
	(segment
		(start 334.781652 -271.482312)
		(end 333.423768 -271.482312)
		(width 0.088646)
		(layer "In2.Cu")
		(net "M_A_CPU0_SA_DQ<11>")
	)
	(segment
		(start 320.191384 -291.913056)
		(end 320.02857 -291.845492)
		(width 0.18288)
		(layer "In2.Cu")
		(net "M_A_CPU0_SA_DQ<11>")
	)
	(segment
		(start 323.069458 -285.475426)
		(end 322.75526 -286.233616)
		(width 0.18288)
		(layer "In2.Cu")
		(net "M_A_CPU0_SA_DQ<11>")
	)
	(segment
		(start 322.75526 -286.233616)
		(end 322.542662 -286.446214)
		(width 0.18288)
		(layer "In2.Cu")
		(net "M_A_CPU0_SA_DQ<11>")
	)
	(segment
		(start 321.37477 -288.59353)
		(end 321.540886 -288.662364)
		(width 0.18288)
		(layer "In2.Cu")
		(net "M_A_CPU0_SA_DQ<11>")
	)
	(segment
		(start 321.992498 -286.602678)
		(end 321.810634 -287.04159)
		(width 0.18288)
		(layer "In2.Cu")
		(net "M_A_CPU0_SA_DQ<11>")
	)
	(segment
		(start 319.497202 -293.149274)
		(end 319.245234 -293.253414)
		(width 0.18288)
		(layer "In2.Cu")
		(net "M_A_CPU0_SA_DQ<11>")
	)
	(segment
		(start 320.315844 -290.649152)
		(end 320.193924 -290.943284)
		(width 0.18288)
		(layer "In2.Cu")
		(net "M_A_CPU0_SA_DQ<11>")
	)
	(segment
		(start 320.026284 -292.815264)
		(end 319.904364 -293.108888)
		(width 0.18288)
		(layer "In2.Cu")
		(net "M_A_CPU0_SA_DQ<11>")
	)
	(segment
		(start 321.27063 -288.341816)
		(end 321.37477 -288.59353)
		(width 0.18288)
		(layer "In2.Cu")
		(net "M_A_CPU0_SA_DQ<11>")
	)
	(segment
		(start 319.654936 -292.243764)
		(end 319.759076 -292.495478)
		(width 0.18288)
		(layer "In2.Cu")
		(net "M_A_CPU0_SA_DQ<11>")
	)
	(segment
		(start 319.904364 -293.108888)
		(end 319.652396 -293.213536)
		(width 0.18288)
		(layer "In2.Cu")
		(net "M_A_CPU0_SA_DQ<11>")
	)
	(segment
		(start 333.423768 -271.482312)
		(end 333.292196 -271.613884)
		(width 0.088646)
		(layer "In2.Cu")
		(net "M_A_CPU0_SA_DQ<11>")
	)
	(segment
		(start 321.915282 -287.293558)
		(end 322.079112 -287.36163)
		(width 0.18288)
		(layer "In2.Cu")
		(net "M_A_CPU0_SA_DQ<11>")
	)
	(segment
		(start 320.443352 -291.808408)
		(end 320.191384 -291.913056)
		(width 0.18288)
		(layer "In2.Cu")
		(net "M_A_CPU0_SA_DQ<11>")
	)
	(segment
		(start 324.721474 -283.82341)
		(end 323.069458 -285.475426)
		(width 0.18288)
		(layer "In2.Cu")
		(net "M_A_CPU0_SA_DQ<11>")
	)
	(segment
		(start 335.5467 -271.34058)
		(end 335.538318 -271.335754)
		(width 0.088646)
		(layer "In2.Cu")
		(net "M_A_CPU0_SA_DQ<11>")
	)
	(segment
		(start 322.079112 -287.36163)
		(end 322.183506 -287.613852)
		(width 0.18288)
		(layer "In2.Cu")
		(net "M_A_CPU0_SA_DQ<11>")
	)
	(segment
		(start 320.460878 -291.262562)
		(end 320.565272 -291.514784)
		(width 0.18288)
		(layer "In2.Cu")
		(net "M_A_CPU0_SA_DQ<11>")
	)
	(segment
		(start 319.759076 -292.495478)
		(end 319.92189 -292.563042)
		(width 0.18288)
		(layer "In2.Cu")
		(net "M_A_CPU0_SA_DQ<11>")
	)
	(segment
		(start 322.183506 -287.613852)
		(end 322.061586 -287.907476)
		(width 0.18288)
		(layer "In2.Cu")
		(net "M_A_CPU0_SA_DQ<11>")
	)
	(segment
		(start 320.98488 -290.508944)
		(end 320.732912 -290.613592)
		(width 0.18288)
		(layer "In2.Cu")
		(net "M_A_CPU0_SA_DQ<11>")
	)
	(segment
		(start 336.290412 -271.011396)
		(end 335.990184 -271.276064)
		(width 0.088646)
		(layer "In2.Cu")
		(net "M_A_CPU0_SA_DQ<11>")
	)
	(segment
		(start 325.899272 -280.980642)
		(end 324.721474 -283.82341)
		(width 0.18288)
		(layer "In2.Cu")
		(net "M_A_CPU0_SA_DQ<11>")
	)
	(segment
		(start 321.810634 -287.04159)
		(end 321.915282 -287.293558)
		(width 0.18288)
		(layer "In2.Cu")
		(net "M_A_CPU0_SA_DQ<11>")
	)
	(segment
		(start 321.540886 -288.662364)
		(end 321.64528 -288.914586)
		(width 0.18288)
		(layer "In2.Cu")
		(net "M_A_CPU0_SA_DQ<11>")
	)
	(segment
		(start 319.245234 -293.253414)
		(end 317.407036 -297.694096)
		(width 0.18288)
		(layer "In2.Cu")
		(net "M_A_CPU0_SA_DQ<11>")
	)
	(segment
		(start 320.02857 -291.845492)
		(end 319.776856 -291.949632)
		(width 0.18288)
		(layer "In2.Cu")
		(net "M_A_CPU0_SA_DQ<11>")
	)
	(segment
		(start 317.407036 -300.496732)
		(end 316.418722 -302.882554)
		(width 0.18288)
		(layer "In2.Cu")
		(net "M_A_CPU0_SA_DQ<11>")
	)
	(segment
		(start 320.732912 -290.613592)
		(end 320.567558 -290.545012)
		(width 0.18288)
		(layer "In2.Cu")
		(net "M_A_CPU0_SA_DQ<11>")
	)
	(segment
		(start 317.407036 -297.694096)
		(end 317.407036 -300.496732)
		(width 0.18288)
		(layer "In2.Cu")
		(net "M_A_CPU0_SA_DQ<11>")
	)
	(segment
		(start 321.1068 -290.21532)
		(end 320.98488 -290.508944)
		(width 0.18288)
		(layer "In2.Cu")
		(net "M_A_CPU0_SA_DQ<11>")
	)
	(segment
		(start 319.652396 -293.213536)
		(end 319.497202 -293.149274)
		(width 0.18288)
		(layer "In2.Cu")
		(net "M_A_CPU0_SA_DQ<11>")
	)
	(segment
		(start 321.106546 -289.244532)
		(end 320.854832 -289.348672)
		(width 0.18288)
		(layer "In2.Cu")
		(net "M_A_CPU0_SA_DQ<11>")
	)
	(segment
		(start 321.809618 -288.012124)
		(end 321.644264 -287.943544)
		(width 0.18288)
		(layer "In2.Cu")
		(net "M_A_CPU0_SA_DQ<11>")
	)
	(segment
		(start 330.997052 -273.909028)
		(end 329.70724 -277.021544)
		(width 0.18288)
		(layer "In2.Cu")
		(net "M_A_CPU0_SA_DQ<11>")
	)
	(segment
		(start 321.002406 -289.963098)
		(end 321.1068 -290.21532)
		(width 0.18288)
		(layer "In2.Cu")
		(net "M_A_CPU0_SA_DQ<11>")
	)
	(segment
		(start 321.64528 -288.914586)
		(end 321.52336 -289.20821)
		(width 0.18288)
		(layer "In2.Cu")
		(net "M_A_CPU0_SA_DQ<11>")
	)
	(segment
		(start 335.538318 -271.335754)
		(end 335.538064 -271.335754)
		(width 0.088646)
		(layer "In2.Cu")
		(net "M_A_CPU0_SA_DQ<11>")
	)
	(segment
		(start 321.644264 -287.943544)
		(end 321.39255 -288.047684)
		(width 0.18288)
		(layer "In2.Cu")
		(net "M_A_CPU0_SA_DQ<11>")
	)
	(segment
		(start 321.52336 -289.20821)
		(end 321.271392 -289.312858)
		(width 0.18288)
		(layer "In2.Cu")
		(net "M_A_CPU0_SA_DQ<11>")
	)
	(segment
		(start 322.061586 -287.907476)
		(end 321.809618 -288.012124)
		(width 0.18288)
		(layer "In2.Cu")
		(net "M_A_CPU0_SA_DQ<11>")
	)
	(arc
		(start 336.477864 -270.687292)
		(mid 336.340641 -270.824189)
		(end 336.290412 -271.011396)
		(width 0.088646)
		(layer "In2.Cu")
		(net "M_A_CPU0_SA_DQ<11>")
	)
	(arc
		(start 334.97266 -271.335754)
		(mid 334.872365 -271.402786)
		(end 334.781652 -271.482312)
		(width 0.088646)
		(layer "In2.Cu")
		(net "M_A_CPU0_SA_DQ<11>")
	)
	(arc
		(start 336.85226 -270.687038)
		(mid 336.665062 -270.636895)
		(end 336.477864 -270.687038)
		(width 0.088646)
		(layer "In2.Cu")
		(net "M_A_CPU0_SA_DQ<11>")
	)
	(arc
		(start 335.990184 -271.276064)
		(mid 335.9534 -271.308326)
		(end 335.912714 -271.3355)
		(width 0.088646)
		(layer "In2.Cu")
		(net "M_A_CPU0_SA_DQ<11>")
	)
	(arc
		(start 337.117182 -270.997172)
		(mid 337.011361 -270.819352)
		(end 336.85226 -270.687038)
		(width 0.088646)
		(layer "In2.Cu")
		(net "M_A_CPU0_SA_DQ<11>")
	)
	(arc
		(start 335.538064 -271.335754)
		(mid 335.255362 -271.259978)
		(end 334.97266 -271.335754)
		(width 0.088646)
		(layer "In2.Cu")
		(net "M_A_CPU0_SA_DQ<11>")
	)
	(arc
		(start 335.91246 -271.335754)
		(mid 335.730209 -271.385865)
		(end 335.5467 -271.34058)
		(width 0.088646)
		(layer "In2.Cu")
		(net "M_A_CPU0_SA_DQ<11>")
	)
	(arc
		(start 337.7565 -271.356582)
		(mid 337.587903 -271.402167)
		(end 337.419188 -271.35709)
		(width 0.088646)
		(layer "In2.Cu")
		(net "M_A_CPU0_SA_DQ<11>")
	)
	(segment
		(start 307.04282 -305.975004)
		(end 306.901088 -306.116736)
		(width 0.20066)
		(layer "F.Cu")
		(net "M_A_CPU0_SA_DQ<10>")
	)
	(segment
		(start 307.76291 -305.67122)
		(end 307.178456 -305.67122)
		(width 0.20066)
		(layer "F.Cu")
		(net "M_A_CPU0_SA_DQ<10>")
	)
	(segment
		(start 311.518046 -306.116482)
		(end 311.339484 -306.295044)
		(width 0.20066)
		(layer "F.Cu")
		(net "M_A_CPU0_SA_DQ<10>")
	)
	(segment
		(start 314.092082 -306.116736)
		(end 312.987182 -306.116736)
		(width 0.20066)
		(layer "F.Cu")
		(net "M_A_CPU0_SA_DQ<10>")
	)
	(segment
		(start 311.043066 -306.295044)
		(end 310.853074 -306.105052)
		(width 0.20066)
		(layer "F.Cu")
		(net "M_A_CPU0_SA_DQ<10>")
	)
	(segment
		(start 311.339484 -306.295044)
		(end 311.043066 -306.295044)
		(width 0.20066)
		(layer "F.Cu")
		(net "M_A_CPU0_SA_DQ<10>")
	)
	(segment
		(start 310.076342 -305.69154)
		(end 307.82768 -305.69154)
		(width 0.1016)
		(layer "F.Cu")
		(net "M_A_CPU0_SA_DQ<10>")
	)
	(segment
		(start 307.04282 -305.806856)
		(end 307.04282 -305.975004)
		(width 0.20066)
		(layer "F.Cu")
		(net "M_A_CPU0_SA_DQ<10>")
	)
	(segment
		(start 312.987182 -306.116736)
		(end 311.5183 -306.116736)
		(width 0.20066)
		(layer "F.Cu")
		(net "M_A_CPU0_SA_DQ<10>")
	)
	(segment
		(start 310.677814 -305.69154)
		(end 310.088026 -305.69154)
		(width 0.20066)
		(layer "F.Cu")
		(net "M_A_CPU0_SA_DQ<10>")
	)
	(segment
		(start 310.088026 -305.69154)
		(end 310.076342 -305.69154)
		(width 0.101854)
		(layer "F.Cu")
		(net "M_A_CPU0_SA_DQ<10>")
	)
	(segment
		(start 307.771038 -305.67122)
		(end 307.76291 -305.67122)
		(width 0.101854)
		(layer "F.Cu")
		(net "M_A_CPU0_SA_DQ<10>")
	)
	(segment
		(start 307.178456 -305.67122)
		(end 307.04282 -305.806856)
		(width 0.20066)
		(layer "F.Cu")
		(net "M_A_CPU0_SA_DQ<10>")
	)
	(segment
		(start 311.5183 -306.116736)
		(end 311.518046 -306.116482)
		(width 0.20066)
		(layer "F.Cu")
		(net "M_A_CPU0_SA_DQ<10>")
	)
	(segment
		(start 310.853074 -305.8668)
		(end 310.677814 -305.69154)
		(width 0.20066)
		(layer "F.Cu")
		(net "M_A_CPU0_SA_DQ<10>")
	)
	(segment
		(start 306.901088 -306.116736)
		(end 305.443382 -306.116736)
		(width 0.20066)
		(layer "F.Cu")
		(net "M_A_CPU0_SA_DQ<10>")
	)
	(segment
		(start 307.791358 -305.69154)
		(end 307.771038 -305.67122)
		(width 0.101854)
		(layer "F.Cu")
		(net "M_A_CPU0_SA_DQ<10>")
	)
	(segment
		(start 310.853074 -306.105052)
		(end 310.853074 -305.8668)
		(width 0.20066)
		(layer "F.Cu")
		(net "M_A_CPU0_SA_DQ<10>")
	)
	(segment
		(start 307.82768 -305.69154)
		(end 307.791358 -305.69154)
		(width 0.101854)
		(layer "F.Cu")
		(net "M_A_CPU0_SA_DQ<10>")
	)
	(segment
		(start 338.074762 -271.289272)
		(end 338.074762 -271.825212)
		(width 0.20066)
		(layer "F.Cu")
		(net "M_A_CPU0_SA_DQ<10>")
	)
	(segment
		(start 320.28257 -295.690036)
		(end 320.387218 -295.942004)
		(width 0.18288)
		(layer "In2.Cu")
		(net "M_A_CPU0_SA_DQ<10>")
	)
	(segment
		(start 334.962754 -272.309336)
		(end 334.95742 -272.319496)
		(width 0.088646)
		(layer "In2.Cu")
		(net "M_A_CPU0_SA_DQ<10>")
	)
	(segment
		(start 314.415424 -306.440078)
		(end 314.092082 -306.116736)
		(width 0.18288)
		(layer "In2.Cu")
		(net "M_A_CPU0_SA_DQ<10>")
	)
	(segment
		(start 319.743582 -296.990516)
		(end 319.84823 -297.242484)
		(width 0.18288)
		(layer "In2.Cu")
		(net "M_A_CPU0_SA_DQ<10>")
	)
	(segment
		(start 319.602104 -296.378376)
		(end 319.480184 -296.672508)
		(width 0.18288)
		(layer "In2.Cu")
		(net "M_A_CPU0_SA_DQ<10>")
	)
	(segment
		(start 320.804032 -294.935148)
		(end 320.552064 -295.039796)
		(width 0.18288)
		(layer "In2.Cu")
		(net "M_A_CPU0_SA_DQ<10>")
	)
	(segment
		(start 332.020926 -274.352258)
		(end 331.876654 -274.49653)
		(width 0.18288)
		(layer "In2.Cu")
		(net "M_A_CPU0_SA_DQ<10>")
	)
	(segment
		(start 327.22693 -282.266898)
		(end 326.974708 -282.371292)
		(width 0.18288)
		(layer "In2.Cu")
		(net "M_A_CPU0_SA_DQ<10>")
	)
	(segment
		(start 320.057018 -295.387776)
		(end 320.161158 -295.63949)
		(width 0.18288)
		(layer "In2.Cu")
		(net "M_A_CPU0_SA_DQ<10>")
	)
	(segment
		(start 334.973422 -272.314924)
		(end 334.972914 -272.314924)
		(width 0.088646)
		(layer "In2.Cu")
		(net "M_A_CPU0_SA_DQ<10>")
	)
	(segment
		(start 319.474088 -297.640756)
		(end 319.315846 -297.575224)
		(width 0.18288)
		(layer "In2.Cu")
		(net "M_A_CPU0_SA_DQ<10>")
	)
	(segment
		(start 327.391776 -281.364436)
		(end 327.496424 -281.616912)
		(width 0.18288)
		(layer "In2.Cu")
		(net "M_A_CPU0_SA_DQ<10>")
	)
	(segment
		(start 319.853818 -296.274236)
		(end 319.602104 -296.378376)
		(width 0.18288)
		(layer "In2.Cu")
		(net "M_A_CPU0_SA_DQ<10>")
	)
	(segment
		(start 335.927446 -272.32356)
		(end 335.912714 -272.314924)
		(width 0.088646)
		(layer "In2.Cu")
		(net "M_A_CPU0_SA_DQ<10>")
	)
	(segment
		(start 317.823088 -303.634648)
		(end 315.017658 -306.440078)
		(width 0.18288)
		(layer "In2.Cu")
		(net "M_A_CPU0_SA_DQ<10>")
	)
	(segment
		(start 335.538572 -272.314924)
		(end 335.528158 -272.32102)
		(width 0.088646)
		(layer "In2.Cu")
		(net "M_A_CPU0_SA_DQ<10>")
	)
	(segment
		(start 318.931036 -300.960028)
		(end 317.823088 -303.634648)
		(width 0.18288)
		(layer "In2.Cu")
		(net "M_A_CPU0_SA_DQ<10>")
	)
	(segment
		(start 325.982076 -284.764988)
		(end 324.334124 -286.41294)
		(width 0.18288)
		(layer "In2.Cu")
		(net "M_A_CPU0_SA_DQ<10>")
	)
	(segment
		(start 320.430652 -294.989504)
		(end 320.178684 -295.093898)
		(width 0.18288)
		(layer "In2.Cu")
		(net "M_A_CPU0_SA_DQ<10>")
	)
	(segment
		(start 320.161158 -295.63949)
		(end 320.28257 -295.690036)
		(width 0.18288)
		(layer "In2.Cu")
		(net "M_A_CPU0_SA_DQ<10>")
	)
	(segment
		(start 338.074762 -271.825212)
		(end 337.762088 -271.825212)
		(width 0.088646)
		(layer "In2.Cu")
		(net "M_A_CPU0_SA_DQ<10>")
	)
	(segment
		(start 319.84823 -297.242484)
		(end 319.72631 -297.536108)
		(width 0.18288)
		(layer "In2.Cu")
		(net "M_A_CPU0_SA_DQ<10>")
	)
	(segment
		(start 326.43572 -283.671264)
		(end 325.982076 -284.764988)
		(width 0.18288)
		(layer "In2.Cu")
		(net "M_A_CPU0_SA_DQ<10>")
	)
	(segment
		(start 326.974708 -282.371292)
		(end 326.853042 -282.664662)
		(width 0.18288)
		(layer "In2.Cu")
		(net "M_A_CPU0_SA_DQ<10>")
	)
	(segment
		(start 320.178684 -295.093898)
		(end 320.057018 -295.387776)
		(width 0.18288)
		(layer "In2.Cu")
		(net "M_A_CPU0_SA_DQ<10>")
	)
	(segment
		(start 320.552064 -295.039796)
		(end 320.430652 -294.989504)
		(width 0.18288)
		(layer "In2.Cu")
		(net "M_A_CPU0_SA_DQ<10>")
	)
	(segment
		(start 324.334124 -286.41294)
		(end 320.804032 -294.935148)
		(width 0.18288)
		(layer "In2.Cu")
		(net "M_A_CPU0_SA_DQ<10>")
	)
	(segment
		(start 326.853042 -282.664662)
		(end 326.957436 -282.916884)
		(width 0.18288)
		(layer "In2.Cu")
		(net "M_A_CPU0_SA_DQ<10>")
	)
	(segment
		(start 327.720706 -281.709876)
		(end 327.8251 -281.962098)
		(width 0.18288)
		(layer "In2.Cu")
		(net "M_A_CPU0_SA_DQ<10>")
	)
	(segment
		(start 319.72631 -297.536108)
		(end 319.474088 -297.640756)
		(width 0.18288)
		(layer "In2.Cu")
		(net "M_A_CPU0_SA_DQ<10>")
	)
	(segment
		(start 315.017658 -306.440078)
		(end 314.415424 -306.440078)
		(width 0.18288)
		(layer "In2.Cu")
		(net "M_A_CPU0_SA_DQ<10>")
	)
	(segment
		(start 327.496424 -281.616912)
		(end 327.720706 -281.709876)
		(width 0.18288)
		(layer "In2.Cu")
		(net "M_A_CPU0_SA_DQ<10>")
	)
	(segment
		(start 326.912224 -283.659834)
		(end 326.687942 -283.56687)
		(width 0.18288)
		(layer "In2.Cu")
		(net "M_A_CPU0_SA_DQ<10>")
	)
	(segment
		(start 331.876654 -274.49653)
		(end 330.524358 -277.76043)
		(width 0.18288)
		(layer "In2.Cu")
		(net "M_A_CPU0_SA_DQ<10>")
	)
	(segment
		(start 327.451212 -282.359862)
		(end 327.22693 -282.266898)
		(width 0.18288)
		(layer "In2.Cu")
		(net "M_A_CPU0_SA_DQ<10>")
	)
	(segment
		(start 337.417664 -272.314924)
		(end 337.40725 -272.32102)
		(width 0.088646)
		(layer "In2.Cu")
		(net "M_A_CPU0_SA_DQ<10>")
	)
	(segment
		(start 318.931036 -298.00042)
		(end 318.931036 -300.960028)
		(width 0.18288)
		(layer "In2.Cu")
		(net "M_A_CPU0_SA_DQ<10>")
	)
	(segment
		(start 319.584324 -296.924222)
		(end 319.743582 -296.990516)
		(width 0.18288)
		(layer "In2.Cu")
		(net "M_A_CPU0_SA_DQ<10>")
	)
	(segment
		(start 327.286112 -283.26207)
		(end 327.164446 -283.55544)
		(width 0.18288)
		(layer "In2.Cu")
		(net "M_A_CPU0_SA_DQ<10>")
	)
	(segment
		(start 320.013076 -296.340276)
		(end 319.853818 -296.274236)
		(width 0.18288)
		(layer "In2.Cu")
		(net "M_A_CPU0_SA_DQ<10>")
	)
	(segment
		(start 327.723246 -280.561542)
		(end 327.391776 -281.364436)
		(width 0.18288)
		(layer "In2.Cu")
		(net "M_A_CPU0_SA_DQ<10>")
	)
	(segment
		(start 333.643224 -272.72996)
		(end 332.020926 -274.352258)
		(width 0.088646)
		(layer "In2.Cu")
		(net "M_A_CPU0_SA_DQ<10>")
	)
	(segment
		(start 327.703434 -282.255468)
		(end 327.451212 -282.359862)
		(width 0.18288)
		(layer "In2.Cu")
		(net "M_A_CPU0_SA_DQ<10>")
	)
	(segment
		(start 326.957436 -282.916884)
		(end 327.181718 -283.009848)
		(width 0.18288)
		(layer "In2.Cu")
		(net "M_A_CPU0_SA_DQ<10>")
	)
	(segment
		(start 320.387218 -295.942004)
		(end 320.265298 -296.235628)
		(width 0.18288)
		(layer "In2.Cu")
		(net "M_A_CPU0_SA_DQ<10>")
	)
	(segment
		(start 335.912714 -272.314924)
		(end 335.904332 -272.310098)
		(width 0.088646)
		(layer "In2.Cu")
		(net "M_A_CPU0_SA_DQ<10>")
	)
	(segment
		(start 319.480184 -296.672508)
		(end 319.584324 -296.924222)
		(width 0.18288)
		(layer "In2.Cu")
		(net "M_A_CPU0_SA_DQ<10>")
	)
	(segment
		(start 334.727042 -272.29054)
		(end 333.716884 -272.681954)
		(width 0.088646)
		(layer "In2.Cu")
		(net "M_A_CPU0_SA_DQ<10>")
	)
	(segment
		(start 330.524358 -277.76043)
		(end 327.723246 -280.561542)
		(width 0.18288)
		(layer "In2.Cu")
		(net "M_A_CPU0_SA_DQ<10>")
	)
	(segment
		(start 327.181718 -283.009848)
		(end 327.286112 -283.26207)
		(width 0.18288)
		(layer "In2.Cu")
		(net "M_A_CPU0_SA_DQ<10>")
	)
	(segment
		(start 337.762088 -271.825212)
		(end 337.69681 -271.89049)
		(width 0.088646)
		(layer "In2.Cu")
		(net "M_A_CPU0_SA_DQ<10>")
	)
	(segment
		(start 327.164446 -283.55544)
		(end 326.912224 -283.659834)
		(width 0.18288)
		(layer "In2.Cu")
		(net "M_A_CPU0_SA_DQ<10>")
	)
	(segment
		(start 319.064132 -297.679364)
		(end 318.931036 -298.00042)
		(width 0.18288)
		(layer "In2.Cu")
		(net "M_A_CPU0_SA_DQ<10>")
	)
	(segment
		(start 326.687942 -283.56687)
		(end 326.43572 -283.671264)
		(width 0.18288)
		(layer "In2.Cu")
		(net "M_A_CPU0_SA_DQ<10>")
	)
	(segment
		(start 319.315846 -297.575224)
		(end 319.064132 -297.679364)
		(width 0.18288)
		(layer "In2.Cu")
		(net "M_A_CPU0_SA_DQ<10>")
	)
	(segment
		(start 320.265298 -296.235628)
		(end 320.013076 -296.340276)
		(width 0.18288)
		(layer "In2.Cu")
		(net "M_A_CPU0_SA_DQ<10>")
	)
	(segment
		(start 327.8251 -281.962098)
		(end 327.703434 -282.255468)
		(width 0.18288)
		(layer "In2.Cu")
		(net "M_A_CPU0_SA_DQ<10>")
	)
	(arc
		(start 333.716884 -272.681954)
		(mid 333.677562 -272.702131)
		(end 333.643224 -272.72996)
		(width 0.088646)
		(layer "In2.Cu")
		(net "M_A_CPU0_SA_DQ<10>")
	)
	(arc
		(start 335.528158 -272.32102)
		(mid 335.24998 -272.390712)
		(end 334.973422 -272.314924)
		(width 0.088646)
		(layer "In2.Cu")
		(net "M_A_CPU0_SA_DQ<10>")
	)
	(arc
		(start 335.904332 -272.310098)
		(mid 335.720824 -272.26482)
		(end 335.538572 -272.314924)
		(width 0.088646)
		(layer "In2.Cu")
		(net "M_A_CPU0_SA_DQ<10>")
	)
	(arc
		(start 337.69681 -271.89049)
		(mid 337.607611 -272.135844)
		(end 337.417664 -272.314924)
		(width 0.088646)
		(layer "In2.Cu")
		(net "M_A_CPU0_SA_DQ<10>")
	)
	(arc
		(start 336.478118 -272.314924)
		(mid 336.203889 -272.390849)
		(end 335.927446 -272.32356)
		(width 0.088646)
		(layer "In2.Cu")
		(net "M_A_CPU0_SA_DQ<10>")
	)
	(arc
		(start 334.95742 -272.319496)
		(mid 334.888461 -272.291211)
		(end 334.81518 -272.277586)
		(width 0.088646)
		(layer "In2.Cu")
		(net "M_A_CPU0_SA_DQ<10>")
	)
	(arc
		(start 336.852514 -272.314924)
		(mid 336.665316 -272.264781)
		(end 336.478118 -272.314924)
		(width 0.088646)
		(layer "In2.Cu")
		(net "M_A_CPU0_SA_DQ<10>")
	)
	(arc
		(start 334.81518 -272.277586)
		(mid 334.770382 -272.279092)
		(end 334.727042 -272.29054)
		(width 0.088646)
		(layer "In2.Cu")
		(net "M_A_CPU0_SA_DQ<10>")
	)
	(arc
		(start 334.972914 -272.314924)
		(mid 334.967855 -272.312092)
		(end 334.962754 -272.309336)
		(width 0.088646)
		(layer "In2.Cu")
		(net "M_A_CPU0_SA_DQ<10>")
	)
	(arc
		(start 337.40725 -272.32102)
		(mid 337.129072 -272.390712)
		(end 336.852514 -272.314924)
		(width 0.088646)
		(layer "In2.Cu")
		(net "M_A_CPU0_SA_DQ<10>")
	)
	(segment
		(start 302.21936 -316.568328)
		(end 302.603408 -316.568328)
		(width 0.20066)
		(layer "F.Cu")
		(net "M_A_CPU0_SA_DQ<0>")
	)
	(segment
		(start 311.94248 -315.875416)
		(end 311.780682 -315.875416)
		(width 0.20066)
		(layer "F.Cu")
		(net "M_A_CPU0_SA_DQ<0>")
	)
	(segment
		(start 316.058042 -316.196726)
		(end 315.796168 -316.088268)
		(width 0.20066)
		(layer "F.Cu")
		(net "M_A_CPU0_SA_DQ<0>")
	)
	(segment
		(start 318.533272 -314.1218)
		(end 317.24473 -314.982606)
		(width 0.20066)
		(layer "F.Cu")
		(net "M_A_CPU0_SA_DQ<0>")
	)
	(segment
		(start 316.453266 -315.81598)
		(end 316.344808 -316.077854)
		(width 0.20066)
		(layer "F.Cu")
		(net "M_A_CPU0_SA_DQ<0>")
	)
	(segment
		(start 304.39868 -315.891672)
		(end 306.55768 -315.891672)
		(width 0.1016)
		(layer "F.Cu")
		(net "M_A_CPU0_SA_DQ<0>")
	)
	(segment
		(start 304.319178 -315.871098)
		(end 304.329084 -315.871098)
		(width 0.101854)
		(layer "F.Cu")
		(net "M_A_CPU0_SA_DQ<0>")
	)
	(segment
		(start 333.375762 -281.05608)
		(end 333.020416 -281.411426)
		(width 0.1016)
		(layer "F.Cu")
		(net "M_A_CPU0_SA_DQ<0>")
	)
	(segment
		(start 302.837596 -316.071758)
		(end 303.038256 -315.871098)
		(width 0.20066)
		(layer "F.Cu")
		(net "M_A_CPU0_SA_DQ<0>")
	)
	(segment
		(start 332.790546 -299.582586)
		(end 332.790546 -299.864526)
		(width 0.1016)
		(layer "F.Cu")
		(net "M_A_CPU0_SA_DQ<0>")
	)
	(segment
		(start 306.644294 -315.891672)
		(end 307.012086 -315.891672)
		(width 0.20066)
		(layer "F.Cu")
		(net "M_A_CPU0_SA_DQ<0>")
	)
	(segment
		(start 332.491588 -299.283628)
		(end 332.790546 -299.582586)
		(width 0.1016)
		(layer "F.Cu")
		(net "M_A_CPU0_SA_DQ<0>")
	)
	(segment
		(start 307.012086 -315.891672)
		(end 307.437028 -316.316614)
		(width 0.20066)
		(layer "F.Cu")
		(net "M_A_CPU0_SA_DQ<0>")
	)
	(segment
		(start 315.796168 -316.088268)
		(end 315.69406 -315.841634)
		(width 0.20066)
		(layer "F.Cu")
		(net "M_A_CPU0_SA_DQ<0>")
	)
	(segment
		(start 311.97804 -315.875416)
		(end 311.94248 -315.875416)
		(width 0.101854)
		(layer "F.Cu")
		(net "M_A_CPU0_SA_DQ<0>")
	)
	(segment
		(start 332.78318 -298.73194)
		(end 332.491588 -299.023532)
		(width 0.1016)
		(layer "F.Cu")
		(net "M_A_CPU0_SA_DQ<0>")
	)
	(segment
		(start 306.55768 -315.891672)
		(end 306.644294 -315.891672)
		(width 0.101854)
		(layer "F.Cu")
		(net "M_A_CPU0_SA_DQ<0>")
	)
	(segment
		(start 314.12688 -315.878464)
		(end 314.084208 -315.878464)
		(width 0.101854)
		(layer "F.Cu")
		(net "M_A_CPU0_SA_DQ<0>")
	)
	(segment
		(start 301.967138 -316.316614)
		(end 301.967392 -316.31636)
		(width 0.20066)
		(layer "F.Cu")
		(net "M_A_CPU0_SA_DQ<0>")
	)
	(segment
		(start 315.69406 -315.841634)
		(end 315.432186 -315.733176)
		(width 0.20066)
		(layer "F.Cu")
		(net "M_A_CPU0_SA_DQ<0>")
	)
	(segment
		(start 303.038256 -315.871098)
		(end 304.319178 -315.871098)
		(width 0.20066)
		(layer "F.Cu")
		(net "M_A_CPU0_SA_DQ<0>")
	)
	(segment
		(start 332.491588 -299.023532)
		(end 332.491588 -299.283628)
		(width 0.1016)
		(layer "F.Cu")
		(net "M_A_CPU0_SA_DQ<0>")
	)
	(segment
		(start 311.994296 -315.891672)
		(end 311.97804 -315.875416)
		(width 0.101854)
		(layer "F.Cu")
		(net "M_A_CPU0_SA_DQ<0>")
	)
	(segment
		(start 317.24473 -314.982606)
		(end 316.459616 -315.307472)
		(width 0.20066)
		(layer "F.Cu")
		(net "M_A_CPU0_SA_DQ<0>")
	)
	(segment
		(start 307.437028 -316.316614)
		(end 308.887114 -316.316614)
		(width 0.20066)
		(layer "F.Cu")
		(net "M_A_CPU0_SA_DQ<0>")
	)
	(segment
		(start 301.967392 -316.31636)
		(end 302.21936 -316.568328)
		(width 0.20066)
		(layer "F.Cu")
		(net "M_A_CPU0_SA_DQ<0>")
	)
	(segment
		(start 316.344808 -316.077854)
		(end 316.058042 -316.196726)
		(width 0.20066)
		(layer "F.Cu")
		(net "M_A_CPU0_SA_DQ<0>")
	)
	(segment
		(start 304.349658 -315.891672)
		(end 304.39868 -315.891672)
		(width 0.101854)
		(layer "F.Cu")
		(net "M_A_CPU0_SA_DQ<0>")
	)
	(segment
		(start 314.084208 -315.878464)
		(end 314.071 -315.891672)
		(width 0.101854)
		(layer "F.Cu")
		(net "M_A_CPU0_SA_DQ<0>")
	)
	(segment
		(start 310.261 -316.316614)
		(end 308.887114 -316.316614)
		(width 0.20066)
		(layer "F.Cu")
		(net "M_A_CPU0_SA_DQ<0>")
	)
	(segment
		(start 304.329084 -315.871098)
		(end 304.349658 -315.891672)
		(width 0.101854)
		(layer "F.Cu")
		(net "M_A_CPU0_SA_DQ<0>")
	)
	(segment
		(start 332.790546 -299.864526)
		(end 332.496922 -300.15815)
		(width 0.1016)
		(layer "F.Cu")
		(net "M_A_CPU0_SA_DQ<0>")
	)
	(segment
		(start 310.875172 -316.182502)
		(end 310.261 -316.316614)
		(width 0.20066)
		(layer "F.Cu")
		(net "M_A_CPU0_SA_DQ<0>")
	)
	(segment
		(start 301.343314 -316.316614)
		(end 301.967138 -316.316614)
		(width 0.20066)
		(layer "F.Cu")
		(net "M_A_CPU0_SA_DQ<0>")
	)
	(segment
		(start 332.78318 -282.593288)
		(end 332.78318 -298.73194)
		(width 0.1016)
		(layer "F.Cu")
		(net "M_A_CPU0_SA_DQ<0>")
	)
	(segment
		(start 302.603408 -316.568328)
		(end 302.837596 -316.33414)
		(width 0.20066)
		(layer "F.Cu")
		(net "M_A_CPU0_SA_DQ<0>")
	)
	(segment
		(start 332.496922 -300.15815)
		(end 318.533272 -314.1218)
		(width 0.20066)
		(layer "F.Cu")
		(net "M_A_CPU0_SA_DQ<0>")
	)
	(segment
		(start 314.071 -315.891672)
		(end 311.994296 -315.891672)
		(width 0.1016)
		(layer "F.Cu")
		(net "M_A_CPU0_SA_DQ<0>")
	)
	(segment
		(start 315.432186 -315.733176)
		(end 314.896754 -315.955172)
		(width 0.20066)
		(layer "F.Cu")
		(net "M_A_CPU0_SA_DQ<0>")
	)
	(segment
		(start 333.020416 -281.411426)
		(end 332.78318 -282.593288)
		(width 0.1016)
		(layer "F.Cu")
		(net "M_A_CPU0_SA_DQ<0>")
	)
	(segment
		(start 314.47105 -315.878464)
		(end 314.12688 -315.878464)
		(width 0.20066)
		(layer "F.Cu")
		(net "M_A_CPU0_SA_DQ<0>")
	)
	(segment
		(start 316.459616 -315.307472)
		(end 316.351158 -315.569346)
		(width 0.20066)
		(layer "F.Cu")
		(net "M_A_CPU0_SA_DQ<0>")
	)
	(segment
		(start 314.547758 -315.955172)
		(end 314.47105 -315.878464)
		(width 0.20066)
		(layer "F.Cu")
		(net "M_A_CPU0_SA_DQ<0>")
	)
	(segment
		(start 316.351158 -315.569346)
		(end 316.453266 -315.81598)
		(width 0.20066)
		(layer "F.Cu")
		(net "M_A_CPU0_SA_DQ<0>")
	)
	(segment
		(start 302.837596 -316.33414)
		(end 302.837596 -316.071758)
		(width 0.20066)
		(layer "F.Cu")
		(net "M_A_CPU0_SA_DQ<0>")
	)
	(segment
		(start 311.780682 -315.875416)
		(end 310.875172 -316.182502)
		(width 0.20066)
		(layer "F.Cu")
		(net "M_A_CPU0_SA_DQ<0>")
	)
	(segment
		(start 314.896754 -315.955172)
		(end 314.547758 -315.955172)
		(width 0.20066)
		(layer "F.Cu")
		(net "M_A_CPU0_SA_DQ<0>")
	)
	(segment
		(start 320.11112 -263.35355)
		(end 316.991238 -266.47394)
		(width 0.20066)
		(layer "F.Cu")
		(net "M_A_CPU0_SA_CS_N<3>")
	)
	(segment
		(start 325.206106 -261.242556)
		(end 325.022464 -261.318756)
		(width 0.20066)
		(layer "F.Cu")
		(net "M_A_CPU0_SA_CS_N<3>")
	)
	(segment
		(start 327.147682 -259.30098)
		(end 325.206106 -261.242556)
		(width 0.20066)
		(layer "F.Cu")
		(net "M_A_CPU0_SA_CS_N<3>")
	)
	(segment
		(start 327.462134 -259.059426)
		(end 327.337674 -259.110988)
		(width 0.1016)
		(layer "F.Cu")
		(net "M_A_CPU0_SA_CS_N<3>")
	)
	(segment
		(start 325.021956 -261.319518)
		(end 320.11112 -263.35355)
		(width 0.20066)
		(layer "F.Cu")
		(net "M_A_CPU0_SA_CS_N<3>")
	)
	(segment
		(start 314.76442 -267.016738)
		(end 312.987182 -267.016738)
		(width 0.20066)
		(layer "F.Cu")
		(net "M_A_CPU0_SA_CS_N<3>")
	)
	(segment
		(start 332.785974 -258.207256)
		(end 331.799692 -258.207256)
		(width 0.088646)
		(layer "F.Cu")
		(net "M_A_CPU0_SA_CS_N<3>")
	)
	(segment
		(start 331.657706 -258.349242)
		(end 330.947522 -259.059426)
		(width 0.1016)
		(layer "F.Cu")
		(net "M_A_CPU0_SA_CS_N<3>")
	)
	(segment
		(start 316.991238 -266.47394)
		(end 315.986922 -266.889992)
		(width 0.20066)
		(layer "F.Cu")
		(net "M_A_CPU0_SA_CS_N<3>")
	)
	(segment
		(start 315.986922 -266.889992)
		(end 314.891166 -266.889992)
		(width 0.20066)
		(layer "F.Cu")
		(net "M_A_CPU0_SA_CS_N<3>")
	)
	(segment
		(start 334.239108 -258.655566)
		(end 334.128364 -258.591558)
		(width 0.088646)
		(layer "F.Cu")
		(net "M_A_CPU0_SA_CS_N<3>")
	)
	(segment
		(start 334.866996 -258.655566)
		(end 334.239108 -258.655566)
		(width 0.088646)
		(layer "F.Cu")
		(net "M_A_CPU0_SA_CS_N<3>")
	)
	(segment
		(start 327.337674 -259.110988)
		(end 327.147682 -259.30098)
		(width 0.101854)
		(layer "F.Cu")
		(net "M_A_CPU0_SA_CS_N<3>")
	)
	(segment
		(start 325.022464 -261.318756)
		(end 325.021956 -261.319518)
		(width 0.20066)
		(layer "F.Cu")
		(net "M_A_CPU0_SA_CS_N<3>")
	)
	(segment
		(start 333.11084 -258.532122)
		(end 332.785974 -258.207256)
		(width 0.088646)
		(layer "F.Cu")
		(net "M_A_CPU0_SA_CS_N<3>")
	)
	(segment
		(start 331.799692 -258.207256)
		(end 331.657706 -258.349242)
		(width 0.088646)
		(layer "F.Cu")
		(net "M_A_CPU0_SA_CS_N<3>")
	)
	(segment
		(start 330.947522 -259.059426)
		(end 327.462134 -259.059426)
		(width 0.1016)
		(layer "F.Cu")
		(net "M_A_CPU0_SA_CS_N<3>")
	)
	(segment
		(start 335.255362 -258.2672)
		(end 334.866996 -258.655566)
		(width 0.088646)
		(layer "F.Cu")
		(net "M_A_CPU0_SA_CS_N<3>")
	)
	(segment
		(start 314.891166 -266.889992)
		(end 314.76442 -267.016738)
		(width 0.20066)
		(layer "F.Cu")
		(net "M_A_CPU0_SA_CS_N<3>")
	)
	(arc
		(start 334.128364 -258.591558)
		(mid 333.845662 -258.515782)
		(end 333.56296 -258.591558)
		(width 0.088646)
		(layer "F.Cu")
		(net "M_A_CPU0_SA_CS_N<3>")
	)
	(arc
		(start 333.188564 -258.591558)
		(mid 333.147755 -258.564386)
		(end 333.11084 -258.532122)
		(width 0.088646)
		(layer "F.Cu")
		(net "M_A_CPU0_SA_CS_N<3>")
	)
	(arc
		(start 333.56296 -258.591558)
		(mid 333.375762 -258.641701)
		(end 333.188564 -258.591558)
		(width 0.088646)
		(layer "F.Cu")
		(net "M_A_CPU0_SA_CS_N<3>")
	)
	(segment
		(start 333.103728 -258.762754)
		(end 332.989174 -258.695698)
		(width 0.088646)
		(layer "F.Cu")
		(net "M_A_CPU0_SA_CS_N<2>")
	)
	(segment
		(start 327.75271 -259.601208)
		(end 325.569834 -261.784084)
		(width 0.20066)
		(layer "F.Cu")
		(net "M_A_CPU0_SA_CS_N<2>")
	)
	(segment
		(start 320.473832 -263.89584)
		(end 317.08979 -267.280136)
		(width 0.20066)
		(layer "F.Cu")
		(net "M_A_CPU0_SA_CS_N<2>")
	)
	(segment
		(start 314.0456 -267.44168)
		(end 311.972452 -267.44168)
		(width 0.1016)
		(layer "F.Cu")
		(net "M_A_CPU0_SA_CS_N<2>")
	)
	(segment
		(start 325.569834 -261.784084)
		(end 325.446898 -261.835138)
		(width 0.20066)
		(layer "F.Cu")
		(net "M_A_CPU0_SA_CS_N<2>")
	)
	(segment
		(start 310.44134 -267.434568)
		(end 310.009286 -267.866622)
		(width 0.20066)
		(layer "F.Cu")
		(net "M_A_CPU0_SA_CS_N<2>")
	)
	(segment
		(start 310.009286 -267.866622)
		(end 308.887114 -267.866622)
		(width 0.20066)
		(layer "F.Cu")
		(net "M_A_CPU0_SA_CS_N<2>")
	)
	(segment
		(start 314.050934 -267.436346)
		(end 314.0456 -267.44168)
		(width 0.101854)
		(layer "F.Cu")
		(net "M_A_CPU0_SA_CS_N<2>")
	)
	(segment
		(start 314.10148 -267.436346)
		(end 314.050934 -267.436346)
		(width 0.101854)
		(layer "F.Cu")
		(net "M_A_CPU0_SA_CS_N<2>")
	)
	(segment
		(start 317.08979 -267.280136)
		(end 316.250066 -267.62837)
		(width 0.20066)
		(layer "F.Cu")
		(net "M_A_CPU0_SA_CS_N<2>")
	)
	(segment
		(start 334.785716 -259.081016)
		(end 334.62214 -258.91744)
		(width 0.088646)
		(layer "F.Cu")
		(net "M_A_CPU0_SA_CS_N<2>")
	)
	(segment
		(start 325.446898 -261.835138)
		(end 325.446136 -261.836408)
		(width 0.20066)
		(layer "F.Cu")
		(net "M_A_CPU0_SA_CS_N<2>")
	)
	(segment
		(start 332.989174 -258.695698)
		(end 332.697582 -258.404106)
		(width 0.088646)
		(layer "F.Cu")
		(net "M_A_CPU0_SA_CS_N<2>")
	)
	(segment
		(start 325.446136 -261.836408)
		(end 320.473832 -263.89584)
		(width 0.20066)
		(layer "F.Cu")
		(net "M_A_CPU0_SA_CS_N<2>")
	)
	(segment
		(start 314.527946 -267.62837)
		(end 314.335922 -267.436346)
		(width 0.20066)
		(layer "F.Cu")
		(net "M_A_CPU0_SA_CS_N<2>")
	)
	(segment
		(start 332.697582 -258.404106)
		(end 332.034134 -258.404106)
		(width 0.088646)
		(layer "F.Cu")
		(net "M_A_CPU0_SA_CS_N<2>")
	)
	(segment
		(start 331.708252 -258.729988)
		(end 331.074014 -259.364226)
		(width 0.1016)
		(layer "F.Cu")
		(net "M_A_CPU0_SA_CS_N<2>")
	)
	(segment
		(start 311.972452 -267.44168)
		(end 311.96534 -267.434568)
		(width 0.101854)
		(layer "F.Cu")
		(net "M_A_CPU0_SA_CS_N<2>")
	)
	(segment
		(start 311.96534 -267.434568)
		(end 311.91708 -267.434568)
		(width 0.101854)
		(layer "F.Cu")
		(net "M_A_CPU0_SA_CS_N<2>")
	)
	(segment
		(start 331.074014 -259.364226)
		(end 328.036936 -259.364226)
		(width 0.1016)
		(layer "F.Cu")
		(net "M_A_CPU0_SA_CS_N<2>")
	)
	(segment
		(start 327.956418 -259.3975)
		(end 327.75271 -259.601208)
		(width 0.101854)
		(layer "F.Cu")
		(net "M_A_CPU0_SA_CS_N<2>")
	)
	(segment
		(start 314.335922 -267.436346)
		(end 314.10148 -267.436346)
		(width 0.20066)
		(layer "F.Cu")
		(net "M_A_CPU0_SA_CS_N<2>")
	)
	(segment
		(start 311.91708 -267.434568)
		(end 310.44134 -267.434568)
		(width 0.20066)
		(layer "F.Cu")
		(net "M_A_CPU0_SA_CS_N<2>")
	)
	(segment
		(start 334.62214 -258.91744)
		(end 334.307688 -258.91744)
		(width 0.088646)
		(layer "F.Cu")
		(net "M_A_CPU0_SA_CS_N<2>")
	)
	(segment
		(start 316.250066 -267.62837)
		(end 314.527946 -267.62837)
		(width 0.20066)
		(layer "F.Cu")
		(net "M_A_CPU0_SA_CS_N<2>")
	)
	(segment
		(start 332.034134 -258.404106)
		(end 331.708252 -258.729988)
		(width 0.088646)
		(layer "F.Cu")
		(net "M_A_CPU0_SA_CS_N<2>")
	)
	(segment
		(start 328.036936 -259.364226)
		(end 327.956418 -259.3975)
		(width 0.1016)
		(layer "F.Cu")
		(net "M_A_CPU0_SA_CS_N<2>")
	)
	(segment
		(start 334.307688 -258.91744)
		(end 334.03286 -258.756658)
		(width 0.088646)
		(layer "F.Cu")
		(net "M_A_CPU0_SA_CS_N<2>")
	)
	(arc
		(start 334.03286 -258.756658)
		(mid 333.845662 -258.706515)
		(end 333.658464 -258.756658)
		(width 0.088646)
		(layer "F.Cu")
		(net "M_A_CPU0_SA_CS_N<2>")
	)
	(arc
		(start 333.658464 -258.756658)
		(mid 333.381905 -258.832401)
		(end 333.103728 -258.762754)
		(width 0.088646)
		(layer "F.Cu")
		(net "M_A_CPU0_SA_CS_N<2>")
	)
	(segment
		(start 331.549502 -258.026154)
		(end 330.82103 -258.754626)
		(width 0.1016)
		(layer "F.Cu")
		(net "M_A_CPU0_SA_CS_N<1>")
	)
	(segment
		(start 307.810916 -266.549124)
		(end 307.76291 -266.549124)
		(width 0.101854)
		(layer "F.Cu")
		(net "M_A_CPU0_SA_CS_N<1>")
	)
	(segment
		(start 330.82103 -258.754626)
		(end 326.789542 -258.754626)
		(width 0.1016)
		(layer "F.Cu")
		(net "M_A_CPU0_SA_CS_N<1>")
	)
	(segment
		(start 311.968896 -266.612878)
		(end 311.94248 -266.612878)
		(width 0.101854)
		(layer "F.Cu")
		(net "M_A_CPU0_SA_CS_N<1>")
	)
	(segment
		(start 333.096108 -257.987546)
		(end 331.58811 -257.987546)
		(width 0.088646)
		(layer "F.Cu")
		(net "M_A_CPU0_SA_CS_N<1>")
	)
	(segment
		(start 311.990232 -266.591542)
		(end 311.968896 -266.612878)
		(width 0.101854)
		(layer "F.Cu")
		(net "M_A_CPU0_SA_CS_N<1>")
	)
	(segment
		(start 324.597522 -260.802882)
		(end 319.640712 -262.855964)
		(width 0.20066)
		(layer "F.Cu")
		(net "M_A_CPU0_SA_CS_N<1>")
	)
	(segment
		(start 306.55768 -266.791186)
		(end 306.332128 -267.016738)
		(width 0.20066)
		(layer "F.Cu")
		(net "M_A_CPU0_SA_CS_N<1>")
	)
	(segment
		(start 326.543162 -259.001006)
		(end 324.843902 -260.700266)
		(width 0.20066)
		(layer "F.Cu")
		(net "M_A_CPU0_SA_CS_N<1>")
	)
	(segment
		(start 306.93868 -266.7127)
		(end 306.860194 -266.791186)
		(width 0.20066)
		(layer "F.Cu")
		(net "M_A_CPU0_SA_CS_N<1>")
	)
	(segment
		(start 306.332128 -267.016738)
		(end 305.443382 -267.016738)
		(width 0.20066)
		(layer "F.Cu")
		(net "M_A_CPU0_SA_CS_N<1>")
	)
	(segment
		(start 333.375762 -258.2672)
		(end 333.096108 -257.987546)
		(width 0.088646)
		(layer "F.Cu")
		(net "M_A_CPU0_SA_CS_N<1>")
	)
	(segment
		(start 314.12688 -266.608052)
		(end 314.119514 -266.608052)
		(width 0.101854)
		(layer "F.Cu")
		(net "M_A_CPU0_SA_CS_N<1>")
	)
	(segment
		(start 306.93868 -266.361926)
		(end 306.93868 -266.7127)
		(width 0.20066)
		(layer "F.Cu")
		(net "M_A_CPU0_SA_CS_N<1>")
	)
	(segment
		(start 314.656978 -266.221972)
		(end 314.270898 -266.608052)
		(width 0.20066)
		(layer "F.Cu")
		(net "M_A_CPU0_SA_CS_N<1>")
	)
	(segment
		(start 307.23205 -266.248896)
		(end 307.05171 -266.248896)
		(width 0.20066)
		(layer "F.Cu")
		(net "M_A_CPU0_SA_CS_N<1>")
	)
	(segment
		(start 316.519814 -265.976862)
		(end 315.928248 -266.221972)
		(width 0.20066)
		(layer "F.Cu")
		(net "M_A_CPU0_SA_CS_N<1>")
	)
	(segment
		(start 319.640712 -262.855964)
		(end 316.519814 -265.976862)
		(width 0.20066)
		(layer "F.Cu")
		(net "M_A_CPU0_SA_CS_N<1>")
	)
	(segment
		(start 311.94248 -266.612878)
		(end 311.7596 -266.612878)
		(width 0.20066)
		(layer "F.Cu")
		(net "M_A_CPU0_SA_CS_N<1>")
	)
	(segment
		(start 307.853334 -266.591542)
		(end 307.810916 -266.549124)
		(width 0.101854)
		(layer "F.Cu")
		(net "M_A_CPU0_SA_CS_N<1>")
	)
	(segment
		(start 307.05171 -266.248896)
		(end 306.93868 -266.361926)
		(width 0.20066)
		(layer "F.Cu")
		(net "M_A_CPU0_SA_CS_N<1>")
	)
	(segment
		(start 314.270898 -266.608052)
		(end 314.12688 -266.608052)
		(width 0.20066)
		(layer "F.Cu")
		(net "M_A_CPU0_SA_CS_N<1>")
	)
	(segment
		(start 307.76291 -266.549124)
		(end 307.532278 -266.549124)
		(width 0.20066)
		(layer "F.Cu")
		(net "M_A_CPU0_SA_CS_N<1>")
	)
	(segment
		(start 310.088026 -266.591542)
		(end 307.853334 -266.591542)
		(width 0.1016)
		(layer "F.Cu")
		(net "M_A_CPU0_SA_CS_N<1>")
	)
	(segment
		(start 311.7596 -266.612878)
		(end 311.738264 -266.591542)
		(width 0.20066)
		(layer "F.Cu")
		(net "M_A_CPU0_SA_CS_N<1>")
	)
	(segment
		(start 331.58811 -257.987546)
		(end 331.549502 -258.026154)
		(width 0.088646)
		(layer "F.Cu")
		(net "M_A_CPU0_SA_CS_N<1>")
	)
	(segment
		(start 315.928248 -266.221972)
		(end 314.656978 -266.221972)
		(width 0.20066)
		(layer "F.Cu")
		(net "M_A_CPU0_SA_CS_N<1>")
	)
	(segment
		(start 311.738264 -266.591542)
		(end 310.088026 -266.591542)
		(width 0.20066)
		(layer "F.Cu")
		(net "M_A_CPU0_SA_CS_N<1>")
	)
	(segment
		(start 324.59803 -260.80212)
		(end 324.597522 -260.802882)
		(width 0.20066)
		(layer "F.Cu")
		(net "M_A_CPU0_SA_CS_N<1>")
	)
	(segment
		(start 326.789542 -258.754626)
		(end 326.543162 -259.001006)
		(width 0.1016)
		(layer "F.Cu")
		(net "M_A_CPU0_SA_CS_N<1>")
	)
	(segment
		(start 314.103004 -266.591542)
		(end 311.990232 -266.591542)
		(width 0.1016)
		(layer "F.Cu")
		(net "M_A_CPU0_SA_CS_N<1>")
	)
	(segment
		(start 306.860194 -266.791186)
		(end 306.55768 -266.791186)
		(width 0.20066)
		(layer "F.Cu")
		(net "M_A_CPU0_SA_CS_N<1>")
	)
	(segment
		(start 324.843902 -260.700266)
		(end 324.59803 -260.80212)
		(width 0.20066)
		(layer "F.Cu")
		(net "M_A_CPU0_SA_CS_N<1>")
	)
	(segment
		(start 307.532278 -266.549124)
		(end 307.23205 -266.248896)
		(width 0.20066)
		(layer "F.Cu")
		(net "M_A_CPU0_SA_CS_N<1>")
	)
	(segment
		(start 314.119514 -266.608052)
		(end 314.103004 -266.591542)
		(width 0.101854)
		(layer "F.Cu")
		(net "M_A_CPU0_SA_CS_N<1>")
	)
	(segment
		(start 307.76291 -268.284198)
		(end 307.796438 -268.284198)
		(width 0.101854)
		(layer "F.Cu")
		(net "M_A_CPU0_SA_CS_N<0>")
	)
	(segment
		(start 311.31637 -268.177772)
		(end 311.43829 -268.299692)
		(width 0.20066)
		(layer "F.Cu")
		(net "M_A_CPU0_SA_CS_N<0>")
	)
	(segment
		(start 306.804314 -267.420852)
		(end 307.66766 -268.284198)
		(width 0.20066)
		(layer "F.Cu")
		(net "M_A_CPU0_SA_CS_N<0>")
	)
	(segment
		(start 314.35294 -268.291564)
		(end 316.32144 -268.291564)
		(width 0.20066)
		(layer "F.Cu")
		(net "M_A_CPU0_SA_CS_N<0>")
	)
	(segment
		(start 333.00416 -259.49148)
		(end 333.414624 -259.081016)
		(width 0.088646)
		(layer "F.Cu")
		(net "M_A_CPU0_SA_CS_N<0>")
	)
	(segment
		(start 333.414624 -259.081016)
		(end 333.845662 -259.081016)
		(width 0.088646)
		(layer "F.Cu")
		(net "M_A_CPU0_SA_CS_N<0>")
	)
	(segment
		(start 306.534312 -267.44168)
		(end 306.55514 -267.420852)
		(width 0.101854)
		(layer "F.Cu")
		(net "M_A_CPU0_SA_CS_N<0>")
	)
	(segment
		(start 307.796438 -268.284198)
		(end 307.803804 -268.291564)
		(width 0.101854)
		(layer "F.Cu")
		(net "M_A_CPU0_SA_CS_N<0>")
	)
	(segment
		(start 310.40578 -268.177772)
		(end 311.31637 -268.177772)
		(width 0.20066)
		(layer "F.Cu")
		(net "M_A_CPU0_SA_CS_N<0>")
	)
	(segment
		(start 320.801492 -264.473182)
		(end 325.895716 -262.36295)
		(width 0.20066)
		(layer "F.Cu")
		(net "M_A_CPU0_SA_CS_N<0>")
	)
	(segment
		(start 326.247506 -262.01116)
		(end 326.250046 -262.010144)
		(width 0.20066)
		(layer "F.Cu")
		(net "M_A_CPU0_SA_CS_N<0>")
	)
	(segment
		(start 303.224438 -267.062458)
		(end 303.52492 -267.062458)
		(width 0.20066)
		(layer "F.Cu")
		(net "M_A_CPU0_SA_CS_N<0>")
	)
	(segment
		(start 310.312562 -268.27099)
		(end 310.40578 -268.177772)
		(width 0.20066)
		(layer "F.Cu")
		(net "M_A_CPU0_SA_CS_N<0>")
	)
	(segment
		(start 317.452248 -267.822426)
		(end 320.801492 -264.473182)
		(width 0.20066)
		(layer "F.Cu")
		(net "M_A_CPU0_SA_CS_N<0>")
	)
	(segment
		(start 311.43829 -268.299692)
		(end 311.89168 -268.299692)
		(width 0.20066)
		(layer "F.Cu")
		(net "M_A_CPU0_SA_CS_N<0>")
	)
	(segment
		(start 301.343314 -267.866622)
		(end 302.420274 -267.866622)
		(width 0.20066)
		(layer "F.Cu")
		(net "M_A_CPU0_SA_CS_N<0>")
	)
	(segment
		(start 311.89168 -268.299692)
		(end 311.899808 -268.291564)
		(width 0.101854)
		(layer "F.Cu")
		(net "M_A_CPU0_SA_CS_N<0>")
	)
	(segment
		(start 331.749146 -259.669026)
		(end 331.981302 -259.669026)
		(width 0.088646)
		(layer "F.Cu")
		(net "M_A_CPU0_SA_CS_N<0>")
	)
	(segment
		(start 307.803804 -268.291564)
		(end 309.9816 -268.291564)
		(width 0.1016)
		(layer "F.Cu")
		(net "M_A_CPU0_SA_CS_N<0>")
	)
	(segment
		(start 325.895716 -262.36295)
		(end 326.247506 -262.01116)
		(width 0.20066)
		(layer "F.Cu")
		(net "M_A_CPU0_SA_CS_N<0>")
	)
	(segment
		(start 304.422556 -267.44168)
		(end 306.534312 -267.44168)
		(width 0.1016)
		(layer "F.Cu")
		(net "M_A_CPU0_SA_CS_N<0>")
	)
	(segment
		(start 306.55514 -267.420852)
		(end 306.60848 -267.420852)
		(width 0.101854)
		(layer "F.Cu")
		(net "M_A_CPU0_SA_CS_N<0>")
	)
	(segment
		(start 310.002174 -268.27099)
		(end 310.03748 -268.27099)
		(width 0.101854)
		(layer "F.Cu")
		(net "M_A_CPU0_SA_CS_N<0>")
	)
	(segment
		(start 302.420274 -267.866622)
		(end 303.224438 -267.062458)
		(width 0.20066)
		(layer "F.Cu")
		(net "M_A_CPU0_SA_CS_N<0>")
	)
	(segment
		(start 310.03748 -268.27099)
		(end 310.312562 -268.27099)
		(width 0.20066)
		(layer "F.Cu")
		(net "M_A_CPU0_SA_CS_N<0>")
	)
	(segment
		(start 328.345546 -259.914644)
		(end 328.591164 -259.669026)
		(width 0.1016)
		(layer "F.Cu")
		(net "M_A_CPU0_SA_CS_N<0>")
	)
	(segment
		(start 307.66766 -268.284198)
		(end 307.76291 -268.284198)
		(width 0.20066)
		(layer "F.Cu")
		(net "M_A_CPU0_SA_CS_N<0>")
	)
	(segment
		(start 304.390806 -267.40993)
		(end 304.422556 -267.44168)
		(width 0.101854)
		(layer "F.Cu")
		(net "M_A_CPU0_SA_CS_N<0>")
	)
	(segment
		(start 331.981302 -259.669026)
		(end 332.158848 -259.49148)
		(width 0.088646)
		(layer "F.Cu")
		(net "M_A_CPU0_SA_CS_N<0>")
	)
	(segment
		(start 332.158848 -259.49148)
		(end 333.00416 -259.49148)
		(width 0.088646)
		(layer "F.Cu")
		(net "M_A_CPU0_SA_CS_N<0>")
	)
	(segment
		(start 303.52492 -267.062458)
		(end 303.872392 -267.40993)
		(width 0.20066)
		(layer "F.Cu")
		(net "M_A_CPU0_SA_CS_N<0>")
	)
	(segment
		(start 303.872392 -267.40993)
		(end 304.34788 -267.40993)
		(width 0.20066)
		(layer "F.Cu")
		(net "M_A_CPU0_SA_CS_N<0>")
	)
	(segment
		(start 309.9816 -268.291564)
		(end 310.002174 -268.27099)
		(width 0.101854)
		(layer "F.Cu")
		(net "M_A_CPU0_SA_CS_N<0>")
	)
	(segment
		(start 306.60848 -267.420852)
		(end 306.804314 -267.420852)
		(width 0.20066)
		(layer "F.Cu")
		(net "M_A_CPU0_SA_CS_N<0>")
	)
	(segment
		(start 326.250046 -262.010144)
		(end 328.345546 -259.914644)
		(width 0.20066)
		(layer "F.Cu")
		(net "M_A_CPU0_SA_CS_N<0>")
	)
	(segment
		(start 304.34788 -267.40993)
		(end 304.390806 -267.40993)
		(width 0.101854)
		(layer "F.Cu")
		(net "M_A_CPU0_SA_CS_N<0>")
	)
	(segment
		(start 316.32144 -268.291564)
		(end 317.452248 -267.822426)
		(width 0.20066)
		(layer "F.Cu")
		(net "M_A_CPU0_SA_CS_N<0>")
	)
	(segment
		(start 311.899808 -268.291564)
		(end 314.295028 -268.291564)
		(width 0.1016)
		(layer "F.Cu")
		(net "M_A_CPU0_SA_CS_N<0>")
	)
	(segment
		(start 314.295028 -268.291564)
		(end 314.35294 -268.291564)
		(width 0.101854)
		(layer "F.Cu")
		(net "M_A_CPU0_SA_CS_N<0>")
	)
	(segment
		(start 328.591164 -259.669026)
		(end 331.749146 -259.669026)
		(width 0.1016)
		(layer "F.Cu")
		(net "M_A_CPU0_SA_CS_N<0>")
	)
	(segment
		(start 335.291176 -260.633718)
		(end 335.291176 -260.3373)
		(width 0.088646)
		(layer "F.Cu")
		(net "M_A_CPU0_SA_CB<7>")
	)
	(segment
		(start 321.328542 -265.564366)
		(end 317.583312 -269.309596)
		(width 0.20066)
		(layer "F.Cu")
		(net "M_A_CPU0_SA_CB<7>")
	)
	(segment
		(start 335.291176 -260.3373)
		(end 335.211928 -260.258052)
		(width 0.088646)
		(layer "F.Cu")
		(net "M_A_CPU0_SA_CB<7>")
	)
	(segment
		(start 311.521856 -270.29283)
		(end 312.035698 -270.29283)
		(width 0.20066)
		(layer "F.Cu")
		(net "M_A_CPU0_SA_CB<7>")
	)
	(segment
		(start 323.267832 -265.142726)
		(end 322.34632 -265.142726)
		(width 0.20066)
		(layer "F.Cu")
		(net "M_A_CPU0_SA_CB<7>")
	)
	(segment
		(start 332.88224 -260.047994)
		(end 332.211934 -260.047994)
		(width 0.088646)
		(layer "F.Cu")
		(net "M_A_CPU0_SA_CB<7>")
	)
	(segment
		(start 332.057248 -260.407404)
		(end 331.811122 -260.65353)
		(width 0.088646)
		(layer "F.Cu")
		(net "M_A_CPU0_SA_CB<7>")
	)
	(segment
		(start 323.589904 -265.927586)
		(end 323.589904 -265.464798)
		(width 0.1016)
		(layer "F.Cu")
		(net "M_A_CPU0_SA_CB<7>")
	)
	(segment
		(start 310.43372 -270.841724)
		(end 310.519318 -270.756126)
		(width 0.20066)
		(layer "F.Cu")
		(net "M_A_CPU0_SA_CB<7>")
	)
	(segment
		(start 307.412136 -270.841724)
		(end 307.636418 -270.841724)
		(width 0.20066)
		(layer "F.Cu")
		(net "M_A_CPU0_SA_CB<7>")
	)
	(segment
		(start 316.622938 -270.26997)
		(end 315.969142 -270.26997)
		(width 0.20066)
		(layer "F.Cu")
		(net "M_A_CPU0_SA_CB<7>")
	)
	(segment
		(start 316.79642 -269.812516)
		(end 316.79642 -270.096488)
		(width 0.20066)
		(layer "F.Cu")
		(net "M_A_CPU0_SA_CB<7>")
	)
	(segment
		(start 317.583312 -269.309596)
		(end 317.29934 -269.309596)
		(width 0.20066)
		(layer "F.Cu")
		(net "M_A_CPU0_SA_CB<7>")
	)
	(segment
		(start 310.06288 -270.841724)
		(end 310.157114 -270.841724)
		(width 0.101854)
		(layer "F.Cu")
		(net "M_A_CPU0_SA_CB<7>")
	)
	(segment
		(start 307.128926 -270.416528)
		(end 307.25491 -270.542512)
		(width 0.20066)
		(layer "F.Cu")
		(net "M_A_CPU0_SA_CB<7>")
	)
	(segment
		(start 332.211934 -260.047994)
		(end 332.057248 -260.20268)
		(width 0.088646)
		(layer "F.Cu")
		(net "M_A_CPU0_SA_CB<7>")
	)
	(segment
		(start 315.768482 -269.560294)
		(end 315.567822 -269.359634)
		(width 0.20066)
		(layer "F.Cu")
		(net "M_A_CPU0_SA_CB<7>")
	)
	(segment
		(start 331.334618 -260.65353)
		(end 329.661012 -260.65353)
		(width 0.1016)
		(layer "F.Cu")
		(net "M_A_CPU0_SA_CB<7>")
	)
	(segment
		(start 314.271152 -270.416528)
		(end 313.469528 -270.416528)
		(width 0.20066)
		(layer "F.Cu")
		(net "M_A_CPU0_SA_CB<7>")
	)
	(segment
		(start 310.781192 -270.067278)
		(end 311.296304 -270.067278)
		(width 0.20066)
		(layer "F.Cu")
		(net "M_A_CPU0_SA_CB<7>")
	)
	(segment
		(start 313.469528 -270.416528)
		(end 313.469274 -270.416782)
		(width 0.20066)
		(layer "F.Cu")
		(net "M_A_CPU0_SA_CB<7>")
	)
	(segment
		(start 317.188088 -269.198344)
		(end 316.904116 -269.198344)
		(width 0.20066)
		(layer "F.Cu")
		(net "M_A_CPU0_SA_CB<7>")
	)
	(segment
		(start 312.15965 -270.416782)
		(end 312.987182 -270.416782)
		(width 0.20066)
		(layer "F.Cu")
		(net "M_A_CPU0_SA_CB<7>")
	)
	(segment
		(start 317.29934 -269.309596)
		(end 317.188088 -269.198344)
		(width 0.20066)
		(layer "F.Cu")
		(net "M_A_CPU0_SA_CB<7>")
	)
	(segment
		(start 333.181198 -260.454394)
		(end 333.181198 -260.346952)
		(width 0.088646)
		(layer "F.Cu")
		(net "M_A_CPU0_SA_CB<7>")
	)
	(segment
		(start 323.55282 -265.427714)
		(end 323.267832 -265.142726)
		(width 0.20066)
		(layer "F.Cu")
		(net "M_A_CPU0_SA_CB<7>")
	)
	(segment
		(start 307.636418 -270.841724)
		(end 307.780944 -270.841724)
		(width 0.101854)
		(layer "F.Cu")
		(net "M_A_CPU0_SA_CB<7>")
	)
	(segment
		(start 310.519318 -270.756126)
		(end 310.519318 -270.329152)
		(width 0.20066)
		(layer "F.Cu")
		(net "M_A_CPU0_SA_CB<7>")
	)
	(segment
		(start 316.904116 -269.198344)
		(end 316.685168 -269.417292)
		(width 0.20066)
		(layer "F.Cu")
		(net "M_A_CPU0_SA_CB<7>")
	)
	(segment
		(start 333.720694 -260.258052)
		(end 333.459836 -260.51891)
		(width 0.088646)
		(layer "F.Cu")
		(net "M_A_CPU0_SA_CB<7>")
	)
	(segment
		(start 315.567822 -269.359634)
		(end 315.257942 -269.359634)
		(width 0.20066)
		(layer "F.Cu")
		(net "M_A_CPU0_SA_CB<7>")
	)
	(segment
		(start 307.25491 -270.542512)
		(end 307.25491 -270.684498)
		(width 0.20066)
		(layer "F.Cu")
		(net "M_A_CPU0_SA_CB<7>")
	)
	(segment
		(start 331.811122 -260.65353)
		(end 331.334618 -260.65353)
		(width 0.088646)
		(layer "F.Cu")
		(net "M_A_CPU0_SA_CB<7>")
	)
	(segment
		(start 305.443382 -270.416782)
		(end 307.128672 -270.416782)
		(width 0.20066)
		(layer "F.Cu")
		(net "M_A_CPU0_SA_CB<7>")
	)
	(segment
		(start 315.057282 -269.560294)
		(end 315.057282 -269.874238)
		(width 0.20066)
		(layer "F.Cu")
		(net "M_A_CPU0_SA_CB<7>")
	)
	(segment
		(start 329.661012 -260.65353)
		(end 324.126352 -266.18819)
		(width 0.1016)
		(layer "F.Cu")
		(net "M_A_CPU0_SA_CB<7>")
	)
	(segment
		(start 334.785716 -260.708902)
		(end 335.215992 -260.708902)
		(width 0.088646)
		(layer "F.Cu")
		(net "M_A_CPU0_SA_CB<7>")
	)
	(segment
		(start 333.181198 -260.346952)
		(end 332.88224 -260.047994)
		(width 0.088646)
		(layer "F.Cu")
		(net "M_A_CPU0_SA_CB<7>")
	)
	(segment
		(start 316.685168 -269.417292)
		(end 316.685168 -269.701264)
		(width 0.20066)
		(layer "F.Cu")
		(net "M_A_CPU0_SA_CB<7>")
	)
	(segment
		(start 324.126352 -266.18819)
		(end 323.850508 -266.18819)
		(width 0.1016)
		(layer "F.Cu")
		(net "M_A_CPU0_SA_CB<7>")
	)
	(segment
		(start 307.25491 -270.684498)
		(end 307.412136 -270.841724)
		(width 0.20066)
		(layer "F.Cu")
		(net "M_A_CPU0_SA_CB<7>")
	)
	(segment
		(start 307.780944 -270.841724)
		(end 310.06288 -270.841724)
		(width 0.1016)
		(layer "F.Cu")
		(net "M_A_CPU0_SA_CB<7>")
	)
	(segment
		(start 315.969142 -270.26997)
		(end 315.768482 -270.06931)
		(width 0.20066)
		(layer "F.Cu")
		(net "M_A_CPU0_SA_CB<7>")
	)
	(segment
		(start 333.245714 -260.51891)
		(end 333.181198 -260.454394)
		(width 0.088646)
		(layer "F.Cu")
		(net "M_A_CPU0_SA_CB<7>")
	)
	(segment
		(start 315.057282 -269.874238)
		(end 314.856622 -270.074898)
		(width 0.20066)
		(layer "F.Cu")
		(net "M_A_CPU0_SA_CB<7>")
	)
	(segment
		(start 311.296304 -270.067278)
		(end 311.521856 -270.29283)
		(width 0.20066)
		(layer "F.Cu")
		(net "M_A_CPU0_SA_CB<7>")
	)
	(segment
		(start 316.79642 -270.096488)
		(end 316.622938 -270.26997)
		(width 0.20066)
		(layer "F.Cu")
		(net "M_A_CPU0_SA_CB<7>")
	)
	(segment
		(start 322.34632 -265.142726)
		(end 321.328542 -265.564366)
		(width 0.20066)
		(layer "F.Cu")
		(net "M_A_CPU0_SA_CB<7>")
	)
	(segment
		(start 314.856622 -270.074898)
		(end 314.612782 -270.074898)
		(width 0.20066)
		(layer "F.Cu")
		(net "M_A_CPU0_SA_CB<7>")
	)
	(segment
		(start 335.215992 -260.708902)
		(end 335.291176 -260.633718)
		(width 0.088646)
		(layer "F.Cu")
		(net "M_A_CPU0_SA_CB<7>")
	)
	(segment
		(start 332.057248 -260.20268)
		(end 332.057248 -260.407404)
		(width 0.088646)
		(layer "F.Cu")
		(net "M_A_CPU0_SA_CB<7>")
	)
	(segment
		(start 323.589904 -265.464798)
		(end 323.55282 -265.427714)
		(width 0.1016)
		(layer "F.Cu")
		(net "M_A_CPU0_SA_CB<7>")
	)
	(segment
		(start 335.211928 -260.258052)
		(end 333.720694 -260.258052)
		(width 0.088646)
		(layer "F.Cu")
		(net "M_A_CPU0_SA_CB<7>")
	)
	(segment
		(start 315.257942 -269.359634)
		(end 315.057282 -269.560294)
		(width 0.20066)
		(layer "F.Cu")
		(net "M_A_CPU0_SA_CB<7>")
	)
	(segment
		(start 310.157114 -270.841724)
		(end 310.43372 -270.841724)
		(width 0.20066)
		(layer "F.Cu")
		(net "M_A_CPU0_SA_CB<7>")
	)
	(segment
		(start 323.850508 -266.18819)
		(end 323.589904 -265.927586)
		(width 0.1016)
		(layer "F.Cu")
		(net "M_A_CPU0_SA_CB<7>")
	)
	(segment
		(start 314.612782 -270.074898)
		(end 314.271152 -270.416528)
		(width 0.20066)
		(layer "F.Cu")
		(net "M_A_CPU0_SA_CB<7>")
	)
	(segment
		(start 310.519318 -270.329152)
		(end 310.781192 -270.067278)
		(width 0.20066)
		(layer "F.Cu")
		(net "M_A_CPU0_SA_CB<7>")
	)
	(segment
		(start 312.035698 -270.29283)
		(end 312.15965 -270.416782)
		(width 0.20066)
		(layer "F.Cu")
		(net "M_A_CPU0_SA_CB<7>")
	)
	(segment
		(start 313.469274 -270.416782)
		(end 312.987182 -270.416782)
		(width 0.20066)
		(layer "F.Cu")
		(net "M_A_CPU0_SA_CB<7>")
	)
	(segment
		(start 333.459836 -260.51891)
		(end 333.245714 -260.51891)
		(width 0.088646)
		(layer "F.Cu")
		(net "M_A_CPU0_SA_CB<7>")
	)
	(segment
		(start 316.685168 -269.701264)
		(end 316.79642 -269.812516)
		(width 0.20066)
		(layer "F.Cu")
		(net "M_A_CPU0_SA_CB<7>")
	)
	(segment
		(start 315.768482 -270.06931)
		(end 315.768482 -269.560294)
		(width 0.20066)
		(layer "F.Cu")
		(net "M_A_CPU0_SA_CB<7>")
	)
	(segment
		(start 307.128672 -270.416782)
		(end 307.128926 -270.416528)
		(width 0.20066)
		(layer "F.Cu")
		(net "M_A_CPU0_SA_CB<7>")
	)
	(segment
		(start 323.274944 -266.575794)
		(end 323.021452 -266.575794)
		(width 0.1016)
		(layer "F.Cu")
		(net "M_A_CPU0_SA_CB<6>")
	)
	(segment
		(start 331.996034 -261.499096)
		(end 331.885036 -261.388098)
		(width 0.088646)
		(layer "F.Cu")
		(net "M_A_CPU0_SA_CB<6>")
	)
	(segment
		(start 315.760608 -271.756632)
		(end 315.760608 -272.040604)
		(width 0.20066)
		(layer "F.Cu")
		(net "M_A_CPU0_SA_CB<6>")
	)
	(segment
		(start 307.04282 -272.014442)
		(end 307.04282 -271.831816)
		(width 0.20066)
		(layer "F.Cu")
		(net "M_A_CPU0_SA_CB<6>")
	)
	(segment
		(start 311.02046 -272.116804)
		(end 312.987182 -272.116804)
		(width 0.20066)
		(layer "F.Cu")
		(net "M_A_CPU0_SA_CB<6>")
	)
	(segment
		(start 333.616808 -261.083298)
		(end 333.6163 -261.083298)
		(width 0.088646)
		(layer "F.Cu")
		(net "M_A_CPU0_SA_CB<6>")
	)
	(segment
		(start 335.154524 -260.904736)
		(end 334.939894 -261.119366)
		(width 0.088646)
		(layer "F.Cu")
		(net "M_A_CPU0_SA_CB<6>")
	)
	(segment
		(start 334.847438 -261.331202)
		(end 334.721454 -261.331202)
		(width 0.088646)
		(layer "F.Cu")
		(net "M_A_CPU0_SA_CB<6>")
	)
	(segment
		(start 334.635094 -261.244842)
		(end 334.635094 -261.142226)
		(width 0.088646)
		(layer "F.Cu")
		(net "M_A_CPU0_SA_CB<6>")
	)
	(segment
		(start 332.18755 -261.499096)
		(end 331.996034 -261.499096)
		(width 0.088646)
		(layer "F.Cu")
		(net "M_A_CPU0_SA_CB<6>")
	)
	(segment
		(start 314.756038 -272.11655)
		(end 314.601352 -272.11655)
		(width 0.20066)
		(layer "F.Cu")
		(net "M_A_CPU0_SA_CB<6>")
	)
	(segment
		(start 306.940458 -272.116804)
		(end 307.04282 -272.014442)
		(width 0.20066)
		(layer "F.Cu")
		(net "M_A_CPU0_SA_CB<6>")
	)
	(segment
		(start 331.885036 -261.388098)
		(end 331.760576 -261.263638)
		(width 0.1016)
		(layer "F.Cu")
		(net "M_A_CPU0_SA_CB<6>")
	)
	(segment
		(start 331.760576 -261.263638)
		(end 329.913996 -261.263638)
		(width 0.1016)
		(layer "F.Cu")
		(net "M_A_CPU0_SA_CB<6>")
	)
	(segment
		(start 314.601352 -272.11655)
		(end 314.60059 -272.116804)
		(width 0.20066)
		(layer "F.Cu")
		(net "M_A_CPU0_SA_CB<6>")
	)
	(segment
		(start 305.443382 -272.116804)
		(end 306.940458 -272.116804)
		(width 0.20066)
		(layer "F.Cu")
		(net "M_A_CPU0_SA_CB<6>")
	)
	(segment
		(start 333.000604 -261.305802)
		(end 332.380844 -261.305802)
		(width 0.088646)
		(layer "F.Cu")
		(net "M_A_CPU0_SA_CB<6>")
	)
	(segment
		(start 333.917036 -261.37743)
		(end 333.791306 -261.37743)
		(width 0.088646)
		(layer "F.Cu")
		(net "M_A_CPU0_SA_CB<6>")
	)
	(segment
		(start 316.557152 -271.867884)
		(end 316.24524 -271.555972)
		(width 0.20066)
		(layer "F.Cu")
		(net "M_A_CPU0_SA_CB<6>")
	)
	(segment
		(start 316.24524 -271.555972)
		(end 315.961268 -271.555972)
		(width 0.20066)
		(layer "F.Cu")
		(net "M_A_CPU0_SA_CB<6>")
	)
	(segment
		(start 315.805312 -272.903696)
		(end 315.38291 -272.903696)
		(width 0.20066)
		(layer "F.Cu")
		(net "M_A_CPU0_SA_CB<6>")
	)
	(segment
		(start 324.269608 -266.908026)
		(end 323.421756 -266.908026)
		(width 0.1016)
		(layer "F.Cu")
		(net "M_A_CPU0_SA_CB<6>")
	)
	(segment
		(start 333.705708 -261.291832)
		(end 333.705708 -261.172198)
		(width 0.088646)
		(layer "F.Cu")
		(net "M_A_CPU0_SA_CB<6>")
	)
	(segment
		(start 323.376798 -266.677648)
		(end 323.274944 -266.575794)
		(width 0.1016)
		(layer "F.Cu")
		(net "M_A_CPU0_SA_CB<6>")
	)
	(segment
		(start 334.635094 -261.142226)
		(end 334.508094 -261.015226)
		(width 0.088646)
		(layer "F.Cu")
		(net "M_A_CPU0_SA_CB<6>")
	)
	(segment
		(start 308.016402 -271.691608)
		(end 310.06288 -271.691608)
		(width 0.1016)
		(layer "F.Cu")
		(net "M_A_CPU0_SA_CB<6>")
	)
	(segment
		(start 334.508094 -261.015226)
		(end 334.132936 -261.015226)
		(width 0.088646)
		(layer "F.Cu")
		(net "M_A_CPU0_SA_CB<6>")
	)
	(segment
		(start 335.359248 -261.108952)
		(end 335.359248 -260.98373)
		(width 0.088646)
		(layer "F.Cu")
		(net "M_A_CPU0_SA_CB<6>")
	)
	(segment
		(start 311.020206 -272.11655)
		(end 311.02046 -272.116804)
		(width 0.20066)
		(layer "F.Cu")
		(net "M_A_CPU0_SA_CB<6>")
	)
	(segment
		(start 307.199538 -271.675098)
		(end 307.628544 -271.675098)
		(width 0.20066)
		(layer "F.Cu")
		(net "M_A_CPU0_SA_CB<6>")
	)
	(segment
		(start 334.005936 -261.142226)
		(end 334.005936 -261.28853)
		(width 0.088646)
		(layer "F.Cu")
		(net "M_A_CPU0_SA_CB<6>")
	)
	(segment
		(start 314.60059 -272.116804)
		(end 312.987182 -272.116804)
		(width 0.20066)
		(layer "F.Cu")
		(net "M_A_CPU0_SA_CB<6>")
	)
	(segment
		(start 310.06288 -271.691608)
		(end 310.14924 -271.691608)
		(width 0.101854)
		(layer "F.Cu")
		(net "M_A_CPU0_SA_CB<6>")
	)
	(segment
		(start 310.891682 -272.245074)
		(end 311.020206 -272.11655)
		(width 0.20066)
		(layer "F.Cu")
		(net "M_A_CPU0_SA_CB<6>")
	)
	(segment
		(start 323.021452 -266.575794)
		(end 322.542408 -266.575794)
		(width 0.20066)
		(layer "F.Cu")
		(net "M_A_CPU0_SA_CB<6>")
	)
	(segment
		(start 310.14924 -271.691608)
		(end 310.316372 -271.691608)
		(width 0.20066)
		(layer "F.Cu")
		(net "M_A_CPU0_SA_CB<6>")
	)
	(segment
		(start 335.359248 -260.98373)
		(end 335.280254 -260.904736)
		(width 0.088646)
		(layer "F.Cu")
		(net "M_A_CPU0_SA_CB<6>")
	)
	(segment
		(start 335.255362 -261.212838)
		(end 335.359248 -261.108952)
		(width 0.088646)
		(layer "F.Cu")
		(net "M_A_CPU0_SA_CB<6>")
	)
	(segment
		(start 316.054232 -272.334228)
		(end 316.054232 -272.654776)
		(width 0.20066)
		(layer "F.Cu")
		(net "M_A_CPU0_SA_CB<6>")
	)
	(segment
		(start 322.542408 -266.575794)
		(end 321.843908 -266.8651)
		(width 0.20066)
		(layer "F.Cu")
		(net "M_A_CPU0_SA_CB<6>")
	)
	(segment
		(start 307.628544 -271.675098)
		(end 307.9623 -271.675098)
		(width 0.101854)
		(layer "F.Cu")
		(net "M_A_CPU0_SA_CB<6>")
	)
	(segment
		(start 307.9623 -271.675098)
		(end 308.016402 -271.691608)
		(width 0.1016)
		(layer "F.Cu")
		(net "M_A_CPU0_SA_CB<6>")
	)
	(segment
		(start 333.791306 -261.37743)
		(end 333.705708 -261.291832)
		(width 0.088646)
		(layer "F.Cu")
		(net "M_A_CPU0_SA_CB<6>")
	)
	(segment
		(start 315.760608 -272.040604)
		(end 316.054232 -272.334228)
		(width 0.20066)
		(layer "F.Cu")
		(net "M_A_CPU0_SA_CB<6>")
	)
	(segment
		(start 334.132936 -261.015226)
		(end 334.005936 -261.142226)
		(width 0.088646)
		(layer "F.Cu")
		(net "M_A_CPU0_SA_CB<6>")
	)
	(segment
		(start 335.255362 -261.522718)
		(end 335.255362 -261.212838)
		(width 0.088646)
		(layer "F.Cu")
		(net "M_A_CPU0_SA_CB<6>")
	)
	(segment
		(start 310.316372 -271.691608)
		(end 310.457088 -271.832324)
		(width 0.20066)
		(layer "F.Cu")
		(net "M_A_CPU0_SA_CB<6>")
	)
	(segment
		(start 334.939894 -261.119366)
		(end 334.939894 -261.238746)
		(width 0.088646)
		(layer "F.Cu")
		(net "M_A_CPU0_SA_CB<6>")
	)
	(segment
		(start 332.380844 -261.305802)
		(end 332.18755 -261.499096)
		(width 0.088646)
		(layer "F.Cu")
		(net "M_A_CPU0_SA_CB<6>")
	)
	(segment
		(start 329.913996 -261.263638)
		(end 324.269608 -266.908026)
		(width 0.1016)
		(layer "F.Cu")
		(net "M_A_CPU0_SA_CB<6>")
	)
	(segment
		(start 333.18704 -261.19836)
		(end 333.000604 -261.305802)
		(width 0.088646)
		(layer "F.Cu")
		(net "M_A_CPU0_SA_CB<6>")
	)
	(segment
		(start 315.961268 -271.555972)
		(end 315.760608 -271.756632)
		(width 0.20066)
		(layer "F.Cu")
		(net "M_A_CPU0_SA_CB<6>")
	)
	(segment
		(start 321.843908 -266.8651)
		(end 316.841124 -271.867884)
		(width 0.20066)
		(layer "F.Cu")
		(net "M_A_CPU0_SA_CB<6>")
	)
	(segment
		(start 334.005936 -261.28853)
		(end 333.917036 -261.37743)
		(width 0.088646)
		(layer "F.Cu")
		(net "M_A_CPU0_SA_CB<6>")
	)
	(segment
		(start 315.18225 -272.703036)
		(end 315.18225 -272.542762)
		(width 0.20066)
		(layer "F.Cu")
		(net "M_A_CPU0_SA_CB<6>")
	)
	(segment
		(start 323.421756 -266.908026)
		(end 323.376798 -266.863068)
		(width 0.1016)
		(layer "F.Cu")
		(net "M_A_CPU0_SA_CB<6>")
	)
	(segment
		(start 315.18225 -272.542762)
		(end 314.756038 -272.11655)
		(width 0.20066)
		(layer "F.Cu")
		(net "M_A_CPU0_SA_CB<6>")
	)
	(segment
		(start 315.38291 -272.903696)
		(end 315.18225 -272.703036)
		(width 0.20066)
		(layer "F.Cu")
		(net "M_A_CPU0_SA_CB<6>")
	)
	(segment
		(start 307.04282 -271.831816)
		(end 307.199538 -271.675098)
		(width 0.20066)
		(layer "F.Cu")
		(net "M_A_CPU0_SA_CB<6>")
	)
	(segment
		(start 323.376798 -266.863068)
		(end 323.376798 -266.677648)
		(width 0.1016)
		(layer "F.Cu")
		(net "M_A_CPU0_SA_CB<6>")
	)
	(segment
		(start 310.457088 -271.832324)
		(end 310.457088 -272.0721)
		(width 0.20066)
		(layer "F.Cu")
		(net "M_A_CPU0_SA_CB<6>")
	)
	(segment
		(start 334.721454 -261.331202)
		(end 334.635094 -261.244842)
		(width 0.088646)
		(layer "F.Cu")
		(net "M_A_CPU0_SA_CB<6>")
	)
	(segment
		(start 310.630062 -272.245074)
		(end 310.891682 -272.245074)
		(width 0.20066)
		(layer "F.Cu")
		(net "M_A_CPU0_SA_CB<6>")
	)
	(segment
		(start 334.939894 -261.238746)
		(end 334.847438 -261.331202)
		(width 0.088646)
		(layer "F.Cu")
		(net "M_A_CPU0_SA_CB<6>")
	)
	(segment
		(start 316.054232 -272.654776)
		(end 315.805312 -272.903696)
		(width 0.20066)
		(layer "F.Cu")
		(net "M_A_CPU0_SA_CB<6>")
	)
	(segment
		(start 335.280254 -260.904736)
		(end 335.154524 -260.904736)
		(width 0.088646)
		(layer "F.Cu")
		(net "M_A_CPU0_SA_CB<6>")
	)
	(segment
		(start 310.457088 -272.0721)
		(end 310.630062 -272.245074)
		(width 0.20066)
		(layer "F.Cu")
		(net "M_A_CPU0_SA_CB<6>")
	)
	(segment
		(start 333.705708 -261.172198)
		(end 333.616808 -261.083298)
		(width 0.088646)
		(layer "F.Cu")
		(net "M_A_CPU0_SA_CB<6>")
	)
	(segment
		(start 316.841124 -271.867884)
		(end 316.557152 -271.867884)
		(width 0.20066)
		(layer "F.Cu")
		(net "M_A_CPU0_SA_CB<6>")
	)
	(arc
		(start 333.6163 -261.083298)
		(mid 333.394088 -261.112554)
		(end 333.18704 -261.19836)
		(width 0.088646)
		(layer "F.Cu")
		(net "M_A_CPU0_SA_CB<6>")
	)
	(segment
		(start 331.925422 -260.958584)
		(end 331.334618 -260.958584)
		(width 0.088646)
		(layer "F.Cu")
		(net "M_A_CPU0_SA_CB<5>")
	)
	(segment
		(start 302.992028 -270.899636)
		(end 303.179734 -270.71193)
		(width 0.20066)
		(layer "F.Cu")
		(net "M_A_CPU0_SA_CB<5>")
	)
	(segment
		(start 332.950058 -261.115302)
		(end 332.08214 -261.115302)
		(width 0.088646)
		(layer "F.Cu")
		(net "M_A_CPU0_SA_CB<5>")
	)
	(segment
		(start 303.179734 -270.71193)
		(end 303.475136 -270.71193)
		(width 0.20066)
		(layer "F.Cu")
		(net "M_A_CPU0_SA_CB<5>")
	)
	(segment
		(start 314.452 -271.691608)
		(end 314.06211 -271.691608)
		(width 0.101854)
		(layer "F.Cu")
		(net "M_A_CPU0_SA_CB<5>")
	)
	(segment
		(start 323.01561 -265.801856)
		(end 322.696332 -265.801856)
		(width 0.20066)
		(layer "F.Cu")
		(net "M_A_CPU0_SA_CB<5>")
	)
	(segment
		(start 324.153022 -266.593066)
		(end 323.80682 -266.593066)
		(width 0.1016)
		(layer "F.Cu")
		(net "M_A_CPU0_SA_CB<5>")
	)
	(segment
		(start 301.343314 -271.266666)
		(end 302.160686 -271.266666)
		(width 0.20066)
		(layer "F.Cu")
		(net "M_A_CPU0_SA_CB<5>")
	)
	(segment
		(start 302.160686 -271.266666)
		(end 302.280574 -271.386554)
		(width 0.20066)
		(layer "F.Cu")
		(net "M_A_CPU0_SA_CB<5>")
	)
	(segment
		(start 303.475136 -270.71193)
		(end 303.60493 -270.841724)
		(width 0.20066)
		(layer "F.Cu")
		(net "M_A_CPU0_SA_CB<5>")
	)
	(segment
		(start 306.60848 -270.841724)
		(end 306.697634 -270.841724)
		(width 0.101854)
		(layer "F.Cu")
		(net "M_A_CPU0_SA_CB<5>")
	)
	(segment
		(start 323.097144 -265.88339)
		(end 323.01561 -265.801856)
		(width 0.20066)
		(layer "F.Cu")
		(net "M_A_CPU0_SA_CB<5>")
	)
	(segment
		(start 333.845662 -260.708902)
		(end 333.845662 -260.708648)
		(width 0.088646)
		(layer "F.Cu")
		(net "M_A_CPU0_SA_CB<5>")
	)
	(segment
		(start 314.762388 -271.441164)
		(end 314.511944 -271.691608)
		(width 0.20066)
		(layer "F.Cu")
		(net "M_A_CPU0_SA_CB<5>")
	)
	(segment
		(start 311.520586 -271.691608)
		(end 311.192672 -271.691608)
		(width 0.20066)
		(layer "F.Cu")
		(net "M_A_CPU0_SA_CB<5>")
	)
	(segment
		(start 314.963302 -270.714978)
		(end 314.762388 -270.915892)
		(width 0.20066)
		(layer "F.Cu")
		(net "M_A_CPU0_SA_CB<5>")
	)
	(segment
		(start 333.487268 -260.80466)
		(end 332.950058 -261.115302)
		(width 0.088646)
		(layer "F.Cu")
		(net "M_A_CPU0_SA_CB<5>")
	)
	(segment
		(start 302.280574 -271.386554)
		(end 302.811688 -271.386554)
		(width 0.20066)
		(layer "F.Cu")
		(net "M_A_CPU0_SA_CB<5>")
	)
	(segment
		(start 321.502024 -266.296648)
		(end 316.883796 -270.914876)
		(width 0.20066)
		(layer "F.Cu")
		(net "M_A_CPU0_SA_CB<5>")
	)
	(segment
		(start 329.787504 -260.958584)
		(end 324.153022 -266.593066)
		(width 0.1016)
		(layer "F.Cu")
		(net "M_A_CPU0_SA_CB<5>")
	)
	(segment
		(start 323.80682 -266.593066)
		(end 323.097144 -265.88339)
		(width 0.1016)
		(layer "F.Cu")
		(net "M_A_CPU0_SA_CB<5>")
	)
	(segment
		(start 302.811688 -271.386554)
		(end 302.992028 -271.206214)
		(width 0.20066)
		(layer "F.Cu")
		(net "M_A_CPU0_SA_CB<5>")
	)
	(segment
		(start 314.511944 -271.691608)
		(end 314.452 -271.691608)
		(width 0.20066)
		(layer "F.Cu")
		(net "M_A_CPU0_SA_CB<5>")
	)
	(segment
		(start 307.246274 -271.266666)
		(end 308.887114 -271.266666)
		(width 0.20066)
		(layer "F.Cu")
		(net "M_A_CPU0_SA_CB<5>")
	)
	(segment
		(start 306.821332 -270.841724)
		(end 307.246274 -271.266666)
		(width 0.20066)
		(layer "F.Cu")
		(net "M_A_CPU0_SA_CB<5>")
	)
	(segment
		(start 311.192672 -271.691608)
		(end 310.76773 -271.266666)
		(width 0.20066)
		(layer "F.Cu")
		(net "M_A_CPU0_SA_CB<5>")
	)
	(segment
		(start 322.696332 -265.801856)
		(end 321.502024 -266.296648)
		(width 0.20066)
		(layer "F.Cu")
		(net "M_A_CPU0_SA_CB<5>")
	)
	(segment
		(start 316.883796 -270.914876)
		(end 315.690758 -270.914876)
		(width 0.20066)
		(layer "F.Cu")
		(net "M_A_CPU0_SA_CB<5>")
	)
	(segment
		(start 315.690758 -270.914876)
		(end 315.49086 -270.714978)
		(width 0.20066)
		(layer "F.Cu")
		(net "M_A_CPU0_SA_CB<5>")
	)
	(segment
		(start 315.49086 -270.714978)
		(end 314.963302 -270.714978)
		(width 0.20066)
		(layer "F.Cu")
		(net "M_A_CPU0_SA_CB<5>")
	)
	(segment
		(start 314.762388 -270.915892)
		(end 314.762388 -271.441164)
		(width 0.20066)
		(layer "F.Cu")
		(net "M_A_CPU0_SA_CB<5>")
	)
	(segment
		(start 304.573432 -270.841724)
		(end 306.60848 -270.841724)
		(width 0.1016)
		(layer "F.Cu")
		(net "M_A_CPU0_SA_CB<5>")
	)
	(segment
		(start 332.08214 -261.115302)
		(end 331.925422 -260.958584)
		(width 0.088646)
		(layer "F.Cu")
		(net "M_A_CPU0_SA_CB<5>")
	)
	(segment
		(start 304.197004 -270.841724)
		(end 304.573432 -270.841724)
		(width 0.101854)
		(layer "F.Cu")
		(net "M_A_CPU0_SA_CB<5>")
	)
	(segment
		(start 310.76773 -271.266666)
		(end 308.887114 -271.266666)
		(width 0.20066)
		(layer "F.Cu")
		(net "M_A_CPU0_SA_CB<5>")
	)
	(segment
		(start 331.334618 -260.958584)
		(end 329.787504 -260.958584)
		(width 0.1016)
		(layer "F.Cu")
		(net "M_A_CPU0_SA_CB<5>")
	)
	(segment
		(start 303.60493 -270.841724)
		(end 304.197004 -270.841724)
		(width 0.20066)
		(layer "F.Cu")
		(net "M_A_CPU0_SA_CB<5>")
	)
	(segment
		(start 333.845662 -260.708648)
		(end 333.487268 -260.80466)
		(width 0.088646)
		(layer "F.Cu")
		(net "M_A_CPU0_SA_CB<5>")
	)
	(segment
		(start 314.06211 -271.691608)
		(end 312.015632 -271.691608)
		(width 0.1016)
		(layer "F.Cu")
		(net "M_A_CPU0_SA_CB<5>")
	)
	(segment
		(start 302.992028 -271.206214)
		(end 302.992028 -270.899636)
		(width 0.20066)
		(layer "F.Cu")
		(net "M_A_CPU0_SA_CB<5>")
	)
	(segment
		(start 306.697634 -270.841724)
		(end 306.821332 -270.841724)
		(width 0.20066)
		(layer "F.Cu")
		(net "M_A_CPU0_SA_CB<5>")
	)
	(segment
		(start 312.015632 -271.691608)
		(end 311.520586 -271.691608)
		(width 0.101854)
		(layer "F.Cu")
		(net "M_A_CPU0_SA_CB<5>")
	)
	(segment
		(start 311.22112 -273.039332)
		(end 311.22112 -272.775172)
		(width 0.20066)
		(layer "F.Cu")
		(net "M_A_CPU0_SA_CB<4>")
	)
	(segment
		(start 332.276704 -261.728458)
		(end 332.482444 -261.522718)
		(width 0.088646)
		(layer "F.Cu")
		(net "M_A_CPU0_SA_CB<4>")
	)
	(segment
		(start 332.482444 -261.522718)
		(end 333.375762 -261.522718)
		(width 0.088646)
		(layer "F.Cu")
		(net "M_A_CPU0_SA_CB<4>")
	)
	(segment
		(start 307.170582 -272.541746)
		(end 307.471572 -272.842736)
		(width 0.20066)
		(layer "F.Cu")
		(net "M_A_CPU0_SA_CB<4>")
	)
	(segment
		(start 323.021452 -267.220446)
		(end 324.388734 -267.220446)
		(width 0.1016)
		(layer "F.Cu")
		(net "M_A_CPU0_SA_CB<4>")
	)
	(segment
		(start 303.984406 -272.541746)
		(end 304.399442 -272.541746)
		(width 0.101854)
		(layer "F.Cu")
		(net "M_A_CPU0_SA_CB<4>")
	)
	(segment
		(start 314.758324 -273.319748)
		(end 314.992766 -273.55419)
		(width 0.20066)
		(layer "F.Cu")
		(net "M_A_CPU0_SA_CB<4>")
	)
	(segment
		(start 311.454546 -272.541746)
		(end 311.522364 -272.541746)
		(width 0.20066)
		(layer "F.Cu")
		(net "M_A_CPU0_SA_CB<4>")
	)
	(segment
		(start 314.992766 -273.55419)
		(end 316.076076 -273.55419)
		(width 0.20066)
		(layer "F.Cu")
		(net "M_A_CPU0_SA_CB<4>")
	)
	(segment
		(start 310.7436 -273.153632)
		(end 311.10682 -273.153632)
		(width 0.20066)
		(layer "F.Cu")
		(net "M_A_CPU0_SA_CB<4>")
	)
	(segment
		(start 303.664112 -272.541746)
		(end 303.984406 -272.541746)
		(width 0.20066)
		(layer "F.Cu")
		(net "M_A_CPU0_SA_CB<4>")
	)
	(segment
		(start 311.22112 -272.775172)
		(end 311.454546 -272.541746)
		(width 0.20066)
		(layer "F.Cu")
		(net "M_A_CPU0_SA_CB<4>")
	)
	(segment
		(start 331.332586 -261.67969)
		(end 331.443584 -261.568692)
		(width 0.088646)
		(layer "F.Cu")
		(net "M_A_CPU0_SA_CB<4>")
	)
	(segment
		(start 322.694046 -267.220446)
		(end 323.021452 -267.220446)
		(width 0.20066)
		(layer "F.Cu")
		(net "M_A_CPU0_SA_CB<4>")
	)
	(segment
		(start 302.187102 -272.966688)
		(end 302.307498 -273.087084)
		(width 0.20066)
		(layer "F.Cu")
		(net "M_A_CPU0_SA_CB<4>")
	)
	(segment
		(start 311.522364 -272.541746)
		(end 311.920382 -272.541746)
		(width 0.101854)
		(layer "F.Cu")
		(net "M_A_CPU0_SA_CB<4>")
	)
	(segment
		(start 301.343314 -272.966688)
		(end 302.187102 -272.966688)
		(width 0.20066)
		(layer "F.Cu")
		(net "M_A_CPU0_SA_CB<4>")
	)
	(segment
		(start 331.443584 -261.568692)
		(end 331.64145 -261.568692)
		(width 0.088646)
		(layer "F.Cu")
		(net "M_A_CPU0_SA_CB<4>")
	)
	(segment
		(start 303.052988 -272.214594)
		(end 303.33696 -272.214594)
		(width 0.20066)
		(layer "F.Cu")
		(net "M_A_CPU0_SA_CB<4>")
	)
	(segment
		(start 302.81245 -272.455132)
		(end 303.052988 -272.214594)
		(width 0.20066)
		(layer "F.Cu")
		(net "M_A_CPU0_SA_CB<4>")
	)
	(segment
		(start 311.10682 -273.153632)
		(end 311.22112 -273.039332)
		(width 0.20066)
		(layer "F.Cu")
		(net "M_A_CPU0_SA_CB<4>")
	)
	(segment
		(start 316.076076 -273.55419)
		(end 322.20916 -267.421106)
		(width 0.20066)
		(layer "F.Cu")
		(net "M_A_CPU0_SA_CB<4>")
	)
	(segment
		(start 314.758324 -272.742406)
		(end 314.758324 -273.319748)
		(width 0.20066)
		(layer "F.Cu")
		(net "M_A_CPU0_SA_CB<4>")
	)
	(segment
		(start 330.040488 -261.568692)
		(end 330.649072 -261.568692)
		(width 0.1016)
		(layer "F.Cu")
		(net "M_A_CPU0_SA_CB<4>")
	)
	(segment
		(start 322.20916 -267.421106)
		(end 322.694046 -267.220446)
		(width 0.20066)
		(layer "F.Cu")
		(net "M_A_CPU0_SA_CB<4>")
	)
	(segment
		(start 302.81245 -272.886424)
		(end 302.81245 -272.455132)
		(width 0.20066)
		(layer "F.Cu")
		(net "M_A_CPU0_SA_CB<4>")
	)
	(segment
		(start 311.920382 -272.541746)
		(end 314.140342 -272.541746)
		(width 0.1016)
		(layer "F.Cu")
		(net "M_A_CPU0_SA_CB<4>")
	)
	(segment
		(start 303.33696 -272.214594)
		(end 303.664112 -272.541746)
		(width 0.20066)
		(layer "F.Cu")
		(net "M_A_CPU0_SA_CB<4>")
	)
	(segment
		(start 331.019404 -261.568692)
		(end 331.130402 -261.67969)
		(width 0.088646)
		(layer "F.Cu")
		(net "M_A_CPU0_SA_CB<4>")
	)
	(segment
		(start 306.911756 -272.541746)
		(end 307.170582 -272.541746)
		(width 0.20066)
		(layer "F.Cu")
		(net "M_A_CPU0_SA_CB<4>")
	)
	(segment
		(start 307.471572 -272.842736)
		(end 307.909722 -272.842736)
		(width 0.20066)
		(layer "F.Cu")
		(net "M_A_CPU0_SA_CB<4>")
	)
	(segment
		(start 310.493664 -272.903696)
		(end 310.7436 -273.153632)
		(width 0.20066)
		(layer "F.Cu")
		(net "M_A_CPU0_SA_CB<4>")
	)
	(segment
		(start 314.453778 -272.541746)
		(end 314.557664 -272.541746)
		(width 0.20066)
		(layer "F.Cu")
		(net "M_A_CPU0_SA_CB<4>")
	)
	(segment
		(start 306.58308 -272.541746)
		(end 306.911756 -272.541746)
		(width 0.101854)
		(layer "F.Cu")
		(net "M_A_CPU0_SA_CB<4>")
	)
	(segment
		(start 309.825644 -272.966688)
		(end 310.11241 -272.903696)
		(width 0.20066)
		(layer "F.Cu")
		(net "M_A_CPU0_SA_CB<4>")
	)
	(segment
		(start 308.887114 -272.966688)
		(end 309.825644 -272.966688)
		(width 0.20066)
		(layer "F.Cu")
		(net "M_A_CPU0_SA_CB<4>")
	)
	(segment
		(start 331.64145 -261.568692)
		(end 331.801216 -261.728458)
		(width 0.088646)
		(layer "F.Cu")
		(net "M_A_CPU0_SA_CB<4>")
	)
	(segment
		(start 304.399442 -272.541746)
		(end 306.58308 -272.541746)
		(width 0.1016)
		(layer "F.Cu")
		(net "M_A_CPU0_SA_CB<4>")
	)
	(segment
		(start 330.649072 -261.568692)
		(end 331.019404 -261.568692)
		(width 0.088646)
		(layer "F.Cu")
		(net "M_A_CPU0_SA_CB<4>")
	)
	(segment
		(start 308.033674 -272.966688)
		(end 308.887114 -272.966688)
		(width 0.20066)
		(layer "F.Cu")
		(net "M_A_CPU0_SA_CB<4>")
	)
	(segment
		(start 310.11241 -272.903696)
		(end 310.493664 -272.903696)
		(width 0.20066)
		(layer "F.Cu")
		(net "M_A_CPU0_SA_CB<4>")
	)
	(segment
		(start 331.801216 -261.728458)
		(end 332.276704 -261.728458)
		(width 0.088646)
		(layer "F.Cu")
		(net "M_A_CPU0_SA_CB<4>")
	)
	(segment
		(start 307.909722 -272.842736)
		(end 308.033674 -272.966688)
		(width 0.20066)
		(layer "F.Cu")
		(net "M_A_CPU0_SA_CB<4>")
	)
	(segment
		(start 324.388734 -267.220446)
		(end 330.040488 -261.568692)
		(width 0.1016)
		(layer "F.Cu")
		(net "M_A_CPU0_SA_CB<4>")
	)
	(segment
		(start 331.130402 -261.67969)
		(end 331.332586 -261.67969)
		(width 0.088646)
		(layer "F.Cu")
		(net "M_A_CPU0_SA_CB<4>")
	)
	(segment
		(start 314.140342 -272.541746)
		(end 314.453778 -272.541746)
		(width 0.101854)
		(layer "F.Cu")
		(net "M_A_CPU0_SA_CB<4>")
	)
	(segment
		(start 302.61179 -273.087084)
		(end 302.81245 -272.886424)
		(width 0.20066)
		(layer "F.Cu")
		(net "M_A_CPU0_SA_CB<4>")
	)
	(segment
		(start 314.557664 -272.541746)
		(end 314.758324 -272.742406)
		(width 0.20066)
		(layer "F.Cu")
		(net "M_A_CPU0_SA_CB<4>")
	)
	(segment
		(start 302.307498 -273.087084)
		(end 302.61179 -273.087084)
		(width 0.20066)
		(layer "F.Cu")
		(net "M_A_CPU0_SA_CB<4>")
	)
	(segment
		(start 316.027054 -276.816058)
		(end 315.65342 -276.442424)
		(width 0.20066)
		(layer "F.Cu")
		(net "M_A_CPU0_SA_CB<3>")
	)
	(segment
		(start 310.020462 -276.791674)
		(end 310.348376 -276.791674)
		(width 0.101854)
		(layer "F.Cu")
		(net "M_A_CPU0_SA_CB<3>")
	)
	(segment
		(start 310.622442 -276.679152)
		(end 310.622442 -276.48408)
		(width 0.20066)
		(layer "F.Cu")
		(net "M_A_CPU0_SA_CB<3>")
	)
	(segment
		(start 335.796636 -263.143238)
		(end 335.796636 -262.851138)
		(width 0.088646)
		(layer "F.Cu")
		(net "M_A_CPU0_SA_CB<3>")
	)
	(segment
		(start 311.23001 -276.28469)
		(end 311.580784 -276.635464)
		(width 0.20066)
		(layer "F.Cu")
		(net "M_A_CPU0_SA_CB<3>")
	)
	(segment
		(start 324.766432 -268.847062)
		(end 324.630034 -268.98346)
		(width 0.1016)
		(layer "F.Cu")
		(net "M_A_CPU0_SA_CB<3>")
	)
	(segment
		(start 335.657698 -262.7122)
		(end 335.510886 -262.726424)
		(width 0.088646)
		(layer "F.Cu")
		(net "M_A_CPU0_SA_CB<3>")
	)
	(segment
		(start 317.361062 -276.051264)
		(end 316.596268 -276.816058)
		(width 0.20066)
		(layer "F.Cu")
		(net "M_A_CPU0_SA_CB<3>")
	)
	(segment
		(start 310.821832 -276.28469)
		(end 311.23001 -276.28469)
		(width 0.20066)
		(layer "F.Cu")
		(net "M_A_CPU0_SA_CB<3>")
	)
	(segment
		(start 331.688948 -263.301226)
		(end 330.464414 -263.301226)
		(width 0.1016)
		(layer "F.Cu")
		(net "M_A_CPU0_SA_CB<3>")
	)
	(segment
		(start 315.65342 -276.442424)
		(end 315.060838 -276.442424)
		(width 0.20066)
		(layer "F.Cu")
		(net "M_A_CPU0_SA_CB<3>")
	)
	(segment
		(start 335.433162 -263.328404)
		(end 335.61147 -263.328404)
		(width 0.088646)
		(layer "F.Cu")
		(net "M_A_CPU0_SA_CB<3>")
	)
	(segment
		(start 332.356968 -263.11098)
		(end 332.09103 -263.221216)
		(width 0.088646)
		(layer "F.Cu")
		(net "M_A_CPU0_SA_CB<3>")
	)
	(segment
		(start 311.580784 -276.635464)
		(end 311.86501 -276.635464)
		(width 0.20066)
		(layer "F.Cu")
		(net "M_A_CPU0_SA_CB<3>")
	)
	(segment
		(start 332.628748 -262.973566)
		(end 332.365858 -263.106916)
		(width 0.088646)
		(layer "F.Cu")
		(net "M_A_CPU0_SA_CB<3>")
	)
	(segment
		(start 332.09103 -263.221216)
		(end 331.909674 -263.257284)
		(width 0.088646)
		(layer "F.Cu")
		(net "M_A_CPU0_SA_CB<3>")
	)
	(segment
		(start 306.94503 -276.366478)
		(end 307.370226 -276.791674)
		(width 0.20066)
		(layer "F.Cu")
		(net "M_A_CPU0_SA_CB<3>")
	)
	(segment
		(start 331.817472 -263.275572)
		(end 331.688948 -263.301226)
		(width 0.1016)
		(layer "F.Cu")
		(net "M_A_CPU0_SA_CB<3>")
	)
	(segment
		(start 310.50992 -276.791674)
		(end 310.622442 -276.679152)
		(width 0.20066)
		(layer "F.Cu")
		(net "M_A_CPU0_SA_CB<3>")
	)
	(segment
		(start 335.796636 -262.851138)
		(end 335.657698 -262.7122)
		(width 0.088646)
		(layer "F.Cu")
		(net "M_A_CPU0_SA_CB<3>")
	)
	(segment
		(start 320.373248 -273.308318)
		(end 320.373248 -273.76501)
		(width 0.20066)
		(layer "F.Cu")
		(net "M_A_CPU0_SA_CB<3>")
	)
	(segment
		(start 335.255362 -263.150604)
		(end 335.433162 -263.328404)
		(width 0.088646)
		(layer "F.Cu")
		(net "M_A_CPU0_SA_CB<3>")
	)
	(segment
		(start 315.060838 -276.442424)
		(end 314.83173 -276.671532)
		(width 0.20066)
		(layer "F.Cu")
		(net "M_A_CPU0_SA_CB<3>")
	)
	(segment
		(start 311.86501 -276.635464)
		(end 312.133742 -276.366732)
		(width 0.20066)
		(layer "F.Cu")
		(net "M_A_CPU0_SA_CB<3>")
	)
	(segment
		(start 319.092834 -275.045424)
		(end 318.636142 -275.045424)
		(width 0.20066)
		(layer "F.Cu")
		(net "M_A_CPU0_SA_CB<3>")
	)
	(segment
		(start 305.443382 -276.366732)
		(end 306.944776 -276.366732)
		(width 0.20066)
		(layer "F.Cu")
		(net "M_A_CPU0_SA_CB<3>")
	)
	(segment
		(start 316.596268 -276.816058)
		(end 316.027054 -276.816058)
		(width 0.20066)
		(layer "F.Cu")
		(net "M_A_CPU0_SA_CB<3>")
	)
	(segment
		(start 306.944776 -276.366732)
		(end 306.94503 -276.366478)
		(width 0.20066)
		(layer "F.Cu")
		(net "M_A_CPU0_SA_CB<3>")
	)
	(segment
		(start 318.361568 -275.319998)
		(end 318.361568 -275.77669)
		(width 0.20066)
		(layer "F.Cu")
		(net "M_A_CPU0_SA_CB<3>")
	)
	(segment
		(start 307.370226 -276.791674)
		(end 307.44922 -276.791674)
		(width 0.20066)
		(layer "F.Cu")
		(net "M_A_CPU0_SA_CB<3>")
	)
	(segment
		(start 310.348376 -276.791674)
		(end 310.50992 -276.791674)
		(width 0.20066)
		(layer "F.Cu")
		(net "M_A_CPU0_SA_CB<3>")
	)
	(segment
		(start 319.367408 -274.314158)
		(end 319.367408 -274.77085)
		(width 0.20066)
		(layer "F.Cu")
		(net "M_A_CPU0_SA_CB<3>")
	)
	(segment
		(start 331.826616 -263.273794)
		(end 331.817472 -263.275572)
		(width 0.088646)
		(layer "F.Cu")
		(net "M_A_CPU0_SA_CB<3>")
	)
	(segment
		(start 324.918578 -268.847062)
		(end 324.766432 -268.847062)
		(width 0.1016)
		(layer "F.Cu")
		(net "M_A_CPU0_SA_CB<3>")
	)
	(segment
		(start 319.641982 -274.039584)
		(end 319.367408 -274.314158)
		(width 0.20066)
		(layer "F.Cu")
		(net "M_A_CPU0_SA_CB<3>")
	)
	(segment
		(start 320.373248 -273.76501)
		(end 320.098674 -274.039584)
		(width 0.20066)
		(layer "F.Cu")
		(net "M_A_CPU0_SA_CB<3>")
	)
	(segment
		(start 334.631792 -262.881364)
		(end 334.566006 -262.862822)
		(width 0.088646)
		(layer "F.Cu")
		(net "M_A_CPU0_SA_CB<3>")
	)
	(segment
		(start 324.034912 -269.646654)
		(end 320.373248 -273.308318)
		(width 0.20066)
		(layer "F.Cu")
		(net "M_A_CPU0_SA_CB<3>")
	)
	(segment
		(start 310.622442 -276.48408)
		(end 310.821832 -276.28469)
		(width 0.20066)
		(layer "F.Cu")
		(net "M_A_CPU0_SA_CB<3>")
	)
	(segment
		(start 307.44922 -276.791674)
		(end 307.79847 -276.791674)
		(width 0.101854)
		(layer "F.Cu")
		(net "M_A_CPU0_SA_CB<3>")
	)
	(segment
		(start 312.133742 -276.366732)
		(end 312.987182 -276.366732)
		(width 0.20066)
		(layer "F.Cu")
		(net "M_A_CPU0_SA_CB<3>")
	)
	(segment
		(start 320.098674 -274.039584)
		(end 319.641982 -274.039584)
		(width 0.20066)
		(layer "F.Cu")
		(net "M_A_CPU0_SA_CB<3>")
	)
	(segment
		(start 318.086994 -276.051264)
		(end 317.361062 -276.051264)
		(width 0.20066)
		(layer "F.Cu")
		(net "M_A_CPU0_SA_CB<3>")
	)
	(segment
		(start 330.464414 -263.301226)
		(end 324.918578 -268.847062)
		(width 0.1016)
		(layer "F.Cu")
		(net "M_A_CPU0_SA_CB<3>")
	)
	(segment
		(start 314.547504 -276.671532)
		(end 314.242704 -276.366732)
		(width 0.20066)
		(layer "F.Cu")
		(net "M_A_CPU0_SA_CB<3>")
	)
	(segment
		(start 318.361568 -275.77669)
		(end 318.086994 -276.051264)
		(width 0.20066)
		(layer "F.Cu")
		(net "M_A_CPU0_SA_CB<3>")
	)
	(segment
		(start 314.83173 -276.671532)
		(end 314.547504 -276.671532)
		(width 0.20066)
		(layer "F.Cu")
		(net "M_A_CPU0_SA_CB<3>")
	)
	(segment
		(start 331.909674 -263.257284)
		(end 331.826616 -263.273794)
		(width 0.088646)
		(layer "F.Cu")
		(net "M_A_CPU0_SA_CB<3>")
	)
	(segment
		(start 335.61147 -263.328404)
		(end 335.796636 -263.143238)
		(width 0.088646)
		(layer "F.Cu")
		(net "M_A_CPU0_SA_CB<3>")
	)
	(segment
		(start 314.242704 -276.366732)
		(end 312.987182 -276.366732)
		(width 0.20066)
		(layer "F.Cu")
		(net "M_A_CPU0_SA_CB<3>")
	)
	(segment
		(start 324.630034 -269.051532)
		(end 324.034912 -269.646654)
		(width 0.1016)
		(layer "F.Cu")
		(net "M_A_CPU0_SA_CB<3>")
	)
	(segment
		(start 319.367408 -274.77085)
		(end 319.092834 -275.045424)
		(width 0.20066)
		(layer "F.Cu")
		(net "M_A_CPU0_SA_CB<3>")
	)
	(segment
		(start 318.636142 -275.045424)
		(end 318.361568 -275.319998)
		(width 0.20066)
		(layer "F.Cu")
		(net "M_A_CPU0_SA_CB<3>")
	)
	(segment
		(start 307.79847 -276.791674)
		(end 310.020462 -276.791674)
		(width 0.1016)
		(layer "F.Cu")
		(net "M_A_CPU0_SA_CB<3>")
	)
	(segment
		(start 324.630034 -268.98346)
		(end 324.630034 -269.051532)
		(width 0.1016)
		(layer "F.Cu")
		(net "M_A_CPU0_SA_CB<3>")
	)
	(arc
		(start 334.287114 -262.78967)
		(mid 334.065282 -262.801879)
		(end 333.843122 -262.80364)
		(width 0.088646)
		(layer "F.Cu")
		(net "M_A_CPU0_SA_CB<3>")
	)
	(arc
		(start 334.288384 -262.78967)
		(mid 334.287749 -262.789669)
		(end 334.287114 -262.78967)
		(width 0.088646)
		(layer "F.Cu")
		(net "M_A_CPU0_SA_CB<3>")
	)
	(arc
		(start 335.236566 -262.776208)
		(mid 335.135526 -262.795479)
		(end 335.043526 -262.841486)
		(width 0.088646)
		(layer "F.Cu")
		(net "M_A_CPU0_SA_CB<3>")
	)
	(arc
		(start 335.009236 -262.855964)
		(mid 334.8227 -262.901181)
		(end 334.631792 -262.881364)
		(width 0.088646)
		(layer "F.Cu")
		(net "M_A_CPU0_SA_CB<3>")
	)
	(arc
		(start 335.510886 -262.726424)
		(mid 335.372682 -262.745563)
		(end 335.236566 -262.776208)
		(width 0.088646)
		(layer "F.Cu")
		(net "M_A_CPU0_SA_CB<3>")
	)
	(arc
		(start 332.365858 -263.106916)
		(mid 332.361452 -263.109034)
		(end 332.356968 -263.11098)
		(width 0.088646)
		(layer "F.Cu")
		(net "M_A_CPU0_SA_CB<3>")
	)
	(arc
		(start 333.12354 -262.869426)
		(mid 332.94095 -262.922385)
		(end 332.751938 -262.942832)
		(width 0.088646)
		(layer "F.Cu")
		(net "M_A_CPU0_SA_CB<3>")
	)
	(arc
		(start 332.751938 -262.942832)
		(mid 332.6886 -262.951216)
		(end 332.628748 -262.973566)
		(width 0.088646)
		(layer "F.Cu")
		(net "M_A_CPU0_SA_CB<3>")
	)
	(arc
		(start 335.043526 -262.841486)
		(mid 335.026341 -262.84863)
		(end 335.009236 -262.855964)
		(width 0.088646)
		(layer "F.Cu")
		(net "M_A_CPU0_SA_CB<3>")
	)
	(arc
		(start 334.566006 -262.862822)
		(mid 334.523881 -262.848438)
		(end 334.483456 -262.829802)
		(width 0.088646)
		(layer "F.Cu")
		(net "M_A_CPU0_SA_CB<3>")
	)
	(arc
		(start 333.404718 -262.78967)
		(mid 333.301337 -262.796241)
		(end 333.204058 -262.831834)
		(width 0.088646)
		(layer "F.Cu")
		(net "M_A_CPU0_SA_CB<3>")
	)
	(arc
		(start 333.204058 -262.831834)
		(mid 333.164383 -262.85188)
		(end 333.12354 -262.869426)
		(width 0.088646)
		(layer "F.Cu")
		(net "M_A_CPU0_SA_CB<3>")
	)
	(arc
		(start 333.843122 -262.80364)
		(mid 333.623754 -262.801877)
		(end 333.404718 -262.78967)
		(width 0.088646)
		(layer "F.Cu")
		(net "M_A_CPU0_SA_CB<3>")
	)
	(arc
		(start 334.483456 -262.829802)
		(mid 334.388734 -262.796062)
		(end 334.288384 -262.78967)
		(width 0.088646)
		(layer "F.Cu")
		(net "M_A_CPU0_SA_CB<3>")
	)
	(segment
		(start 331.813408 -263.984486)
		(end 331.571854 -263.984486)
		(width 0.088646)
		(layer "F.Cu")
		(net "M_A_CPU0_SA_CB<2>")
	)
	(segment
		(start 331.571854 -263.984486)
		(end 331.432662 -263.845294)
		(width 0.088646)
		(layer "F.Cu")
		(net "M_A_CPU0_SA_CB<2>")
	)
	(segment
		(start 334.196436 -263.804654)
		(end 334.120744 -263.728962)
		(width 0.088646)
		(layer "F.Cu")
		(net "M_A_CPU0_SA_CB<2>")
	)
	(segment
		(start 305.443382 -278.066754)
		(end 306.940458 -278.066754)
		(width 0.20066)
		(layer "F.Cu")
		(net "M_A_CPU0_SA_CB<2>")
	)
	(segment
		(start 321.734688 -273.854926)
		(end 321.54114 -274.322286)
		(width 0.20066)
		(layer "F.Cu")
		(net "M_A_CPU0_SA_CB<2>")
	)
	(segment
		(start 315.209682 -278.172926)
		(end 315.209428 -278.172672)
		(width 0.20066)
		(layer "F.Cu")
		(net "M_A_CPU0_SA_CB<2>")
	)
	(segment
		(start 320.556128 -276.026118)
		(end 320.326512 -276.255734)
		(width 0.20066)
		(layer "F.Cu")
		(net "M_A_CPU0_SA_CB<2>")
	)
	(segment
		(start 322.203826 -273.291808)
		(end 322.019676 -273.736816)
		(width 0.20066)
		(layer "F.Cu")
		(net "M_A_CPU0_SA_CB<2>")
	)
	(segment
		(start 320.756788 -275.249894)
		(end 320.556128 -275.450554)
		(width 0.20066)
		(layer "F.Cu")
		(net "M_A_CPU0_SA_CB<2>")
	)
	(segment
		(start 332.519528 -263.470898)
		(end 332.51013 -263.470898)
		(width 0.088646)
		(layer "F.Cu")
		(net "M_A_CPU0_SA_CB<2>")
	)
	(segment
		(start 333.521812 -263.550908)
		(end 333.366364 -263.550908)
		(width 0.088646)
		(layer "F.Cu")
		(net "M_A_CPU0_SA_CB<2>")
	)
	(segment
		(start 330.567538 -264.06094)
		(end 324.737984 -269.890494)
		(width 0.1016)
		(layer "F.Cu")
		(net "M_A_CPU0_SA_CB<2>")
	)
	(segment
		(start 321.332352 -275.249894)
		(end 320.756788 -275.249894)
		(width 0.20066)
		(layer "F.Cu")
		(net "M_A_CPU0_SA_CB<2>")
	)
	(segment
		(start 315.209428 -278.172672)
		(end 314.635134 -278.172672)
		(width 0.20066)
		(layer "F.Cu")
		(net "M_A_CPU0_SA_CB<2>")
	)
	(segment
		(start 311.020206 -278.0665)
		(end 311.02046 -278.066754)
		(width 0.20066)
		(layer "F.Cu")
		(net "M_A_CPU0_SA_CB<2>")
	)
	(segment
		(start 333.92872 -263.275826)
		(end 333.796894 -263.275826)
		(width 0.088646)
		(layer "F.Cu")
		(net "M_A_CPU0_SA_CB<2>")
	)
	(segment
		(start 319.550288 -276.456394)
		(end 319.550288 -277.031958)
		(width 0.20066)
		(layer "F.Cu")
		(net "M_A_CPU0_SA_CB<2>")
	)
	(segment
		(start 310.108854 -277.641558)
		(end 310.372506 -277.641558)
		(width 0.20066)
		(layer "F.Cu")
		(net "M_A_CPU0_SA_CB<2>")
	)
	(segment
		(start 332.918562 -263.39673)
		(end 332.896464 -263.39673)
		(width 0.088646)
		(layer "F.Cu")
		(net "M_A_CPU0_SA_CB<2>")
	)
	(segment
		(start 318.544448 -278.037798)
		(end 318.40932 -278.172926)
		(width 0.20066)
		(layer "F.Cu")
		(net "M_A_CPU0_SA_CB<2>")
	)
	(segment
		(start 306.940458 -278.066754)
		(end 307.04282 -277.964392)
		(width 0.20066)
		(layer "F.Cu")
		(net "M_A_CPU0_SA_CB<2>")
	)
	(segment
		(start 331.267308 -263.845294)
		(end 331.188822 -263.92378)
		(width 0.088646)
		(layer "F.Cu")
		(net "M_A_CPU0_SA_CB<2>")
	)
	(segment
		(start 307.82768 -277.641558)
		(end 310.06288 -277.641558)
		(width 0.1016)
		(layer "F.Cu")
		(net "M_A_CPU0_SA_CB<2>")
	)
	(segment
		(start 314.635134 -278.172672)
		(end 314.529216 -278.066754)
		(width 0.20066)
		(layer "F.Cu")
		(net "M_A_CPU0_SA_CB<2>")
	)
	(segment
		(start 307.04282 -277.767796)
		(end 307.169058 -277.641558)
		(width 0.20066)
		(layer "F.Cu")
		(net "M_A_CPU0_SA_CB<2>")
	)
	(segment
		(start 310.457088 -277.72614)
		(end 310.457088 -278.02205)
		(width 0.20066)
		(layer "F.Cu")
		(net "M_A_CPU0_SA_CB<2>")
	)
	(segment
		(start 307.652674 -277.641558)
		(end 307.82768 -277.641558)
		(width 0.101854)
		(layer "F.Cu")
		(net "M_A_CPU0_SA_CB<2>")
	)
	(segment
		(start 321.435476 -275.14677)
		(end 321.332352 -275.249894)
		(width 0.20066)
		(layer "F.Cu")
		(net "M_A_CPU0_SA_CB<2>")
	)
	(segment
		(start 333.796894 -263.275826)
		(end 333.521812 -263.550908)
		(width 0.088646)
		(layer "F.Cu")
		(net "M_A_CPU0_SA_CB<2>")
	)
	(segment
		(start 321.54114 -274.322286)
		(end 321.65925 -274.607274)
		(width 0.20066)
		(layer "F.Cu")
		(net "M_A_CPU0_SA_CB<2>")
	)
	(segment
		(start 334.785716 -263.858756)
		(end 334.731614 -263.804654)
		(width 0.088646)
		(layer "F.Cu")
		(net "M_A_CPU0_SA_CB<2>")
	)
	(segment
		(start 334.785716 -263.96442)
		(end 334.785716 -263.858756)
		(width 0.088646)
		(layer "F.Cu")
		(net "M_A_CPU0_SA_CB<2>")
	)
	(segment
		(start 332.51013 -263.470898)
		(end 332.135734 -263.845294)
		(width 0.088646)
		(layer "F.Cu")
		(net "M_A_CPU0_SA_CB<2>")
	)
	(segment
		(start 307.04282 -277.964392)
		(end 307.04282 -277.767796)
		(width 0.20066)
		(layer "F.Cu")
		(net "M_A_CPU0_SA_CB<2>")
	)
	(segment
		(start 334.120744 -263.728962)
		(end 334.120744 -263.46785)
		(width 0.088646)
		(layer "F.Cu")
		(net "M_A_CPU0_SA_CB<2>")
	)
	(segment
		(start 332.135734 -263.845294)
		(end 331.9526 -263.845294)
		(width 0.088646)
		(layer "F.Cu")
		(net "M_A_CPU0_SA_CB<2>")
	)
	(segment
		(start 310.457088 -278.02205)
		(end 310.606186 -278.171148)
		(width 0.20066)
		(layer "F.Cu")
		(net "M_A_CPU0_SA_CB<2>")
	)
	(segment
		(start 331.008736 -263.92378)
		(end 330.937362 -263.852406)
		(width 0.088646)
		(layer "F.Cu")
		(net "M_A_CPU0_SA_CB<2>")
	)
	(segment
		(start 324.034912 -271.460722)
		(end 322.203826 -273.291808)
		(width 0.20066)
		(layer "F.Cu")
		(net "M_A_CPU0_SA_CB<2>")
	)
	(segment
		(start 319.750948 -276.255734)
		(end 319.550288 -276.456394)
		(width 0.20066)
		(layer "F.Cu")
		(net "M_A_CPU0_SA_CB<2>")
	)
	(segment
		(start 322.019676 -273.736816)
		(end 321.734688 -273.854926)
		(width 0.20066)
		(layer "F.Cu")
		(net "M_A_CPU0_SA_CB<2>")
	)
	(segment
		(start 307.169058 -277.641558)
		(end 307.652674 -277.641558)
		(width 0.20066)
		(layer "F.Cu")
		(net "M_A_CPU0_SA_CB<2>")
	)
	(segment
		(start 310.915558 -278.171148)
		(end 311.020206 -278.0665)
		(width 0.20066)
		(layer "F.Cu")
		(net "M_A_CPU0_SA_CB<2>")
	)
	(segment
		(start 332.739238 -263.404096)
		(end 332.519528 -263.470898)
		(width 0.088646)
		(layer "F.Cu")
		(net "M_A_CPU0_SA_CB<2>")
	)
	(segment
		(start 319.550288 -277.031958)
		(end 319.320672 -277.261574)
		(width 0.20066)
		(layer "F.Cu")
		(net "M_A_CPU0_SA_CB<2>")
	)
	(segment
		(start 332.877922 -263.39673)
		(end 332.739238 -263.404096)
		(width 0.088646)
		(layer "F.Cu")
		(net "M_A_CPU0_SA_CB<2>")
	)
	(segment
		(start 334.731614 -263.804654)
		(end 334.196436 -263.804654)
		(width 0.088646)
		(layer "F.Cu")
		(net "M_A_CPU0_SA_CB<2>")
	)
	(segment
		(start 318.40932 -278.172926)
		(end 315.209682 -278.172926)
		(width 0.20066)
		(layer "F.Cu")
		(net "M_A_CPU0_SA_CB<2>")
	)
	(segment
		(start 310.372506 -277.641558)
		(end 310.457088 -277.72614)
		(width 0.20066)
		(layer "F.Cu")
		(net "M_A_CPU0_SA_CB<2>")
	)
	(segment
		(start 334.120744 -263.46785)
		(end 333.92872 -263.275826)
		(width 0.088646)
		(layer "F.Cu")
		(net "M_A_CPU0_SA_CB<2>")
	)
	(segment
		(start 331.188822 -263.92378)
		(end 331.008736 -263.92378)
		(width 0.088646)
		(layer "F.Cu")
		(net "M_A_CPU0_SA_CB<2>")
	)
	(segment
		(start 321.65925 -274.607274)
		(end 321.435476 -275.14677)
		(width 0.20066)
		(layer "F.Cu")
		(net "M_A_CPU0_SA_CB<2>")
	)
	(segment
		(start 320.556128 -275.450554)
		(end 320.556128 -276.026118)
		(width 0.20066)
		(layer "F.Cu")
		(net "M_A_CPU0_SA_CB<2>")
	)
	(segment
		(start 331.9526 -263.845294)
		(end 331.813408 -263.984486)
		(width 0.088646)
		(layer "F.Cu")
		(net "M_A_CPU0_SA_CB<2>")
	)
	(segment
		(start 331.432662 -263.845294)
		(end 331.267308 -263.845294)
		(width 0.088646)
		(layer "F.Cu")
		(net "M_A_CPU0_SA_CB<2>")
	)
	(segment
		(start 314.529216 -278.066754)
		(end 312.987182 -278.066754)
		(width 0.20066)
		(layer "F.Cu")
		(net "M_A_CPU0_SA_CB<2>")
	)
	(segment
		(start 324.125082 -271.370552)
		(end 324.034912 -271.460722)
		(width 0.1016)
		(layer "F.Cu")
		(net "M_A_CPU0_SA_CB<2>")
	)
	(segment
		(start 330.776072 -263.852406)
		(end 330.567538 -264.06094)
		(width 0.088646)
		(layer "F.Cu")
		(net "M_A_CPU0_SA_CB<2>")
	)
	(segment
		(start 310.606186 -278.171148)
		(end 310.915558 -278.171148)
		(width 0.20066)
		(layer "F.Cu")
		(net "M_A_CPU0_SA_CB<2>")
	)
	(segment
		(start 310.06288 -277.641558)
		(end 310.108854 -277.641558)
		(width 0.101854)
		(layer "F.Cu")
		(net "M_A_CPU0_SA_CB<2>")
	)
	(segment
		(start 332.896464 -263.39673)
		(end 332.895702 -263.396476)
		(width 0.088646)
		(layer "F.Cu")
		(net "M_A_CPU0_SA_CB<2>")
	)
	(segment
		(start 324.737984 -269.890494)
		(end 324.125082 -271.370552)
		(width 0.1016)
		(layer "F.Cu")
		(net "M_A_CPU0_SA_CB<2>")
	)
	(segment
		(start 319.320672 -277.261574)
		(end 318.745108 -277.261574)
		(width 0.20066)
		(layer "F.Cu")
		(net "M_A_CPU0_SA_CB<2>")
	)
	(segment
		(start 318.745108 -277.261574)
		(end 318.544448 -277.462234)
		(width 0.20066)
		(layer "F.Cu")
		(net "M_A_CPU0_SA_CB<2>")
	)
	(segment
		(start 311.02046 -278.066754)
		(end 312.987182 -278.066754)
		(width 0.20066)
		(layer "F.Cu")
		(net "M_A_CPU0_SA_CB<2>")
	)
	(segment
		(start 318.544448 -277.462234)
		(end 318.544448 -278.037798)
		(width 0.20066)
		(layer "F.Cu")
		(net "M_A_CPU0_SA_CB<2>")
	)
	(segment
		(start 330.937362 -263.852406)
		(end 330.776072 -263.852406)
		(width 0.088646)
		(layer "F.Cu")
		(net "M_A_CPU0_SA_CB<2>")
	)
	(segment
		(start 320.326512 -276.255734)
		(end 319.750948 -276.255734)
		(width 0.20066)
		(layer "F.Cu")
		(net "M_A_CPU0_SA_CB<2>")
	)
	(arc
		(start 332.895702 -263.396476)
		(mid 332.886811 -263.396544)
		(end 332.877922 -263.39673)
		(width 0.088646)
		(layer "F.Cu")
		(net "M_A_CPU0_SA_CB<2>")
	)
	(arc
		(start 333.18704 -263.475216)
		(mid 333.139915 -263.450692)
		(end 333.090774 -263.430512)
		(width 0.088646)
		(layer "F.Cu")
		(net "M_A_CPU0_SA_CB<2>")
	)
	(arc
		(start 333.090774 -263.430512)
		(mid 333.057544 -263.419711)
		(end 333.023718 -263.410954)
		(width 0.088646)
		(layer "F.Cu")
		(net "M_A_CPU0_SA_CB<2>")
	)
	(arc
		(start 333.023718 -263.410954)
		(mid 332.971461 -263.401467)
		(end 332.918562 -263.39673)
		(width 0.088646)
		(layer "F.Cu")
		(net "M_A_CPU0_SA_CB<2>")
	)
	(arc
		(start 333.366364 -263.550908)
		(mid 333.274347 -263.518639)
		(end 333.18704 -263.475216)
		(width 0.088646)
		(layer "F.Cu")
		(net "M_A_CPU0_SA_CB<2>")
	)
	(segment
		(start 304.319178 -276.76475)
		(end 304.346102 -276.791674)
		(width 0.101854)
		(layer "F.Cu")
		(net "M_A_CPU0_SA_CB<1>")
	)
	(segment
		(start 311.743598 -277.641558)
		(end 312.12536 -277.641558)
		(width 0.101854)
		(layer "F.Cu")
		(net "M_A_CPU0_SA_CB<1>")
	)
	(segment
		(start 324.359524 -269.966186)
		(end 324.359524 -269.837408)
		(width 0.1016)
		(layer "F.Cu")
		(net "M_A_CPU0_SA_CB<1>")
	)
	(segment
		(start 306.698396 -276.791674)
		(end 306.778914 -276.791674)
		(width 0.20066)
		(layer "F.Cu")
		(net "M_A_CPU0_SA_CB<1>")
	)
	(segment
		(start 303.28108 -276.466554)
		(end 303.572672 -276.466554)
		(width 0.20066)
		(layer "F.Cu")
		(net "M_A_CPU0_SA_CB<1>")
	)
	(segment
		(start 303.572672 -276.466554)
		(end 303.870868 -276.76475)
		(width 0.20066)
		(layer "F.Cu")
		(net "M_A_CPU0_SA_CB<1>")
	)
	(segment
		(start 314.14466 -277.641558)
		(end 314.199778 -277.641558)
		(width 0.101854)
		(layer "F.Cu")
		(net "M_A_CPU0_SA_CB<1>")
	)
	(segment
		(start 312.12536 -277.641558)
		(end 314.14466 -277.641558)
		(width 0.1016)
		(layer "F.Cu")
		(net "M_A_CPU0_SA_CB<1>")
	)
	(segment
		(start 302.812196 -277.335742)
		(end 303.068482 -277.079456)
		(width 0.20066)
		(layer "F.Cu")
		(net "M_A_CPU0_SA_CB<1>")
	)
	(segment
		(start 310.767222 -277.216616)
		(end 311.192164 -277.641558)
		(width 0.20066)
		(layer "F.Cu")
		(net "M_A_CPU0_SA_CB<1>")
	)
	(segment
		(start 303.068482 -277.079456)
		(end 303.068482 -276.679152)
		(width 0.20066)
		(layer "F.Cu")
		(net "M_A_CPU0_SA_CB<1>")
	)
	(segment
		(start 320.913252 -274.145756)
		(end 321.246246 -273.3421)
		(width 0.20066)
		(layer "F.Cu")
		(net "M_A_CPU0_SA_CB<1>")
	)
	(segment
		(start 324.198234 -270.390112)
		(end 324.198234 -270.127476)
		(width 0.1016)
		(layer "F.Cu")
		(net "M_A_CPU0_SA_CB<1>")
	)
	(segment
		(start 314.36818 -277.641558)
		(end 314.532772 -277.476966)
		(width 0.20066)
		(layer "F.Cu")
		(net "M_A_CPU0_SA_CB<1>")
	)
	(segment
		(start 311.192164 -277.641558)
		(end 311.743598 -277.641558)
		(width 0.20066)
		(layer "F.Cu")
		(net "M_A_CPU0_SA_CB<1>")
	)
	(segment
		(start 317.582042 -277.476966)
		(end 320.913252 -274.145756)
		(width 0.20066)
		(layer "F.Cu")
		(net "M_A_CPU0_SA_CB<1>")
	)
	(segment
		(start 304.855626 -276.791674)
		(end 306.60848 -276.791674)
		(width 0.1016)
		(layer "F.Cu")
		(net "M_A_CPU0_SA_CB<1>")
	)
	(segment
		(start 306.778914 -276.791674)
		(end 307.203856 -277.216616)
		(width 0.20066)
		(layer "F.Cu")
		(net "M_A_CPU0_SA_CB<1>")
	)
	(segment
		(start 324.034912 -270.553434)
		(end 324.198234 -270.390112)
		(width 0.1016)
		(layer "F.Cu")
		(net "M_A_CPU0_SA_CB<1>")
	)
	(segment
		(start 330.526644 -263.670288)
		(end 330.588366 -263.608566)
		(width 0.088646)
		(layer "F.Cu")
		(net "M_A_CPU0_SA_CB<1>")
	)
	(segment
		(start 306.60848 -276.791674)
		(end 306.698396 -276.791674)
		(width 0.101854)
		(layer "F.Cu")
		(net "M_A_CPU0_SA_CB<1>")
	)
	(segment
		(start 307.203856 -277.216616)
		(end 308.887114 -277.216616)
		(width 0.20066)
		(layer "F.Cu")
		(net "M_A_CPU0_SA_CB<1>")
	)
	(segment
		(start 304.346102 -276.791674)
		(end 304.855626 -276.791674)
		(width 0.101854)
		(layer "F.Cu")
		(net "M_A_CPU0_SA_CB<1>")
	)
	(segment
		(start 324.359524 -269.837408)
		(end 330.526644 -263.670288)
		(width 0.1016)
		(layer "F.Cu")
		(net "M_A_CPU0_SA_CB<1>")
	)
	(segment
		(start 302.3235 -277.335742)
		(end 302.812196 -277.335742)
		(width 0.20066)
		(layer "F.Cu")
		(net "M_A_CPU0_SA_CB<1>")
	)
	(segment
		(start 314.532772 -277.476966)
		(end 317.582042 -277.476966)
		(width 0.20066)
		(layer "F.Cu")
		(net "M_A_CPU0_SA_CB<1>")
	)
	(segment
		(start 302.204374 -277.216616)
		(end 302.3235 -277.335742)
		(width 0.20066)
		(layer "F.Cu")
		(net "M_A_CPU0_SA_CB<1>")
	)
	(segment
		(start 321.246246 -273.3421)
		(end 324.034912 -270.553434)
		(width 0.20066)
		(layer "F.Cu")
		(net "M_A_CPU0_SA_CB<1>")
	)
	(segment
		(start 303.068482 -276.679152)
		(end 303.28108 -276.466554)
		(width 0.20066)
		(layer "F.Cu")
		(net "M_A_CPU0_SA_CB<1>")
	)
	(segment
		(start 301.343314 -277.216616)
		(end 302.204374 -277.216616)
		(width 0.20066)
		(layer "F.Cu")
		(net "M_A_CPU0_SA_CB<1>")
	)
	(segment
		(start 332.700376 -263.150604)
		(end 333.375762 -263.150604)
		(width 0.088646)
		(layer "F.Cu")
		(net "M_A_CPU0_SA_CB<1>")
	)
	(segment
		(start 303.870868 -276.76475)
		(end 304.319178 -276.76475)
		(width 0.20066)
		(layer "F.Cu")
		(net "M_A_CPU0_SA_CB<1>")
	)
	(segment
		(start 331.856842 -263.608566)
		(end 332.700376 -263.150604)
		(width 0.088646)
		(layer "F.Cu")
		(net "M_A_CPU0_SA_CB<1>")
	)
	(segment
		(start 324.198234 -270.127476)
		(end 324.359524 -269.966186)
		(width 0.1016)
		(layer "F.Cu")
		(net "M_A_CPU0_SA_CB<1>")
	)
	(segment
		(start 314.199778 -277.641558)
		(end 314.36818 -277.641558)
		(width 0.20066)
		(layer "F.Cu")
		(net "M_A_CPU0_SA_CB<1>")
	)
	(segment
		(start 330.588366 -263.608566)
		(end 331.856842 -263.608566)
		(width 0.088646)
		(layer "F.Cu")
		(net "M_A_CPU0_SA_CB<1>")
	)
	(segment
		(start 308.887114 -277.216616)
		(end 310.767222 -277.216616)
		(width 0.20066)
		(layer "F.Cu")
		(net "M_A_CPU0_SA_CB<1>")
	)
	(segment
		(start 330.62037 -264.4394)
		(end 325.014844 -270.044926)
		(width 0.1016)
		(layer "F.Cu")
		(net "M_A_CPU0_SA_CB<0>")
	)
	(segment
		(start 306.68214 -278.491696)
		(end 307.037486 -278.491696)
		(width 0.20066)
		(layer "F.Cu")
		(net "M_A_CPU0_SA_CB<0>")
	)
	(segment
		(start 303.264062 -278.319738)
		(end 303.69256 -278.319738)
		(width 0.20066)
		(layer "F.Cu")
		(net "M_A_CPU0_SA_CB<0>")
	)
	(segment
		(start 302.971454 -278.856186)
		(end 302.971454 -278.612346)
		(width 0.20066)
		(layer "F.Cu")
		(net "M_A_CPU0_SA_CB<0>")
	)
	(segment
		(start 302.971454 -278.612346)
		(end 303.264062 -278.319738)
		(width 0.20066)
		(layer "F.Cu")
		(net "M_A_CPU0_SA_CB<0>")
	)
	(segment
		(start 318.677544 -278.82088)
		(end 314.68568 -278.82088)
		(width 0.20066)
		(layer "F.Cu")
		(net "M_A_CPU0_SA_CB<0>")
	)
	(segment
		(start 314.230004 -278.491696)
		(end 313.849512 -278.491696)
		(width 0.101854)
		(layer "F.Cu")
		(net "M_A_CPU0_SA_CB<0>")
	)
	(segment
		(start 307.037486 -278.491696)
		(end 307.462428 -278.916638)
		(width 0.20066)
		(layer "F.Cu")
		(net "M_A_CPU0_SA_CB<0>")
	)
	(segment
		(start 333.260192 -263.737852)
		(end 333.088742 -263.638792)
		(width 0.088646)
		(layer "F.Cu")
		(net "M_A_CPU0_SA_CB<0>")
	)
	(segment
		(start 306.60848 -278.491696)
		(end 306.68214 -278.491696)
		(width 0.101854)
		(layer "F.Cu")
		(net "M_A_CPU0_SA_CB<0>")
	)
	(segment
		(start 332.707996 -263.627108)
		(end 332.545436 -263.714484)
		(width 0.088646)
		(layer "F.Cu")
		(net "M_A_CPU0_SA_CB<0>")
	)
	(segment
		(start 333.845662 -263.96442)
		(end 333.260192 -263.737852)
		(width 0.088646)
		(layer "F.Cu")
		(net "M_A_CPU0_SA_CB<0>")
	)
	(segment
		(start 309.771542 -278.882602)
		(end 309.689246 -278.916638)
		(width 0.20066)
		(layer "F.Cu")
		(net "M_A_CPU0_SA_CB<0>")
	)
	(segment
		(start 323.55028 -272.856198)
		(end 322.761356 -273.645122)
		(width 0.20066)
		(layer "F.Cu")
		(net "M_A_CPU0_SA_CB<0>")
	)
	(segment
		(start 303.69256 -278.319738)
		(end 303.864518 -278.491696)
		(width 0.20066)
		(layer "F.Cu")
		(net "M_A_CPU0_SA_CB<0>")
	)
	(segment
		(start 311.743344 -278.470868)
		(end 311.203848 -278.470868)
		(width 0.20066)
		(layer "F.Cu")
		(net "M_A_CPU0_SA_CB<0>")
	)
	(segment
		(start 303.864518 -278.491696)
		(end 304.221896 -278.491696)
		(width 0.20066)
		(layer "F.Cu")
		(net "M_A_CPU0_SA_CB<0>")
	)
	(segment
		(start 314.335668 -278.470868)
		(end 314.250832 -278.470868)
		(width 0.20066)
		(layer "F.Cu")
		(net "M_A_CPU0_SA_CB<0>")
	)
	(segment
		(start 313.849512 -278.491696)
		(end 312.156856 -278.491696)
		(width 0.1016)
		(layer "F.Cu")
		(net "M_A_CPU0_SA_CB<0>")
	)
	(segment
		(start 302.803306 -279.024334)
		(end 302.971454 -278.856186)
		(width 0.20066)
		(layer "F.Cu")
		(net "M_A_CPU0_SA_CB<0>")
	)
	(segment
		(start 314.250832 -278.470868)
		(end 314.230004 -278.491696)
		(width 0.101854)
		(layer "F.Cu")
		(net "M_A_CPU0_SA_CB<0>")
	)
	(segment
		(start 301.343314 -278.916638)
		(end 302.192182 -278.916638)
		(width 0.20066)
		(layer "F.Cu")
		(net "M_A_CPU0_SA_CB<0>")
	)
	(segment
		(start 330.854304 -264.205466)
		(end 330.62037 -264.4394)
		(width 0.088646)
		(layer "F.Cu")
		(net "M_A_CPU0_SA_CB<0>")
	)
	(segment
		(start 309.689246 -278.916638)
		(end 308.887114 -278.916638)
		(width 0.20066)
		(layer "F.Cu")
		(net "M_A_CPU0_SA_CB<0>")
	)
	(segment
		(start 311.077102 -278.597614)
		(end 309.771542 -278.882602)
		(width 0.20066)
		(layer "F.Cu")
		(net "M_A_CPU0_SA_CB<0>")
	)
	(segment
		(start 302.192182 -278.916638)
		(end 302.299878 -279.024334)
		(width 0.20066)
		(layer "F.Cu")
		(net "M_A_CPU0_SA_CB<0>")
	)
	(segment
		(start 304.221896 -278.491696)
		(end 304.319178 -278.491696)
		(width 0.101854)
		(layer "F.Cu")
		(net "M_A_CPU0_SA_CB<0>")
	)
	(segment
		(start 332.545436 -263.714484)
		(end 332.054454 -264.205466)
		(width 0.088646)
		(layer "F.Cu")
		(net "M_A_CPU0_SA_CB<0>")
	)
	(segment
		(start 332.054454 -264.205466)
		(end 330.854304 -264.205466)
		(width 0.088646)
		(layer "F.Cu")
		(net "M_A_CPU0_SA_CB<0>")
	)
	(segment
		(start 312.156856 -278.491696)
		(end 311.764172 -278.491696)
		(width 0.101854)
		(layer "F.Cu")
		(net "M_A_CPU0_SA_CB<0>")
	)
	(segment
		(start 304.319178 -278.491696)
		(end 306.60848 -278.491696)
		(width 0.1016)
		(layer "F.Cu")
		(net "M_A_CPU0_SA_CB<0>")
	)
	(segment
		(start 321.988942 -275.509482)
		(end 318.677544 -278.82088)
		(width 0.20066)
		(layer "F.Cu")
		(net "M_A_CPU0_SA_CB<0>")
	)
	(segment
		(start 311.203848 -278.470868)
		(end 311.077102 -278.597614)
		(width 0.20066)
		(layer "F.Cu")
		(net "M_A_CPU0_SA_CB<0>")
	)
	(segment
		(start 325.014844 -270.044926)
		(end 324.062598 -272.34388)
		(width 0.1016)
		(layer "F.Cu")
		(net "M_A_CPU0_SA_CB<0>")
	)
	(segment
		(start 322.761356 -273.645122)
		(end 321.988942 -275.509482)
		(width 0.20066)
		(layer "F.Cu")
		(net "M_A_CPU0_SA_CB<0>")
	)
	(segment
		(start 324.062598 -272.34388)
		(end 323.55028 -272.856198)
		(width 0.1016)
		(layer "F.Cu")
		(net "M_A_CPU0_SA_CB<0>")
	)
	(segment
		(start 314.68568 -278.82088)
		(end 314.335668 -278.470868)
		(width 0.20066)
		(layer "F.Cu")
		(net "M_A_CPU0_SA_CB<0>")
	)
	(segment
		(start 307.462428 -278.916638)
		(end 308.887114 -278.916638)
		(width 0.20066)
		(layer "F.Cu")
		(net "M_A_CPU0_SA_CB<0>")
	)
	(segment
		(start 302.299878 -279.024334)
		(end 302.803306 -279.024334)
		(width 0.20066)
		(layer "F.Cu")
		(net "M_A_CPU0_SA_CB<0>")
	)
	(segment
		(start 311.764172 -278.491696)
		(end 311.743344 -278.470868)
		(width 0.101854)
		(layer "F.Cu")
		(net "M_A_CPU0_SA_CB<0>")
	)
	(arc
		(start 332.89621 -263.586976)
		(mid 332.799972 -263.597059)
		(end 332.707996 -263.627108)
		(width 0.088646)
		(layer "F.Cu")
		(net "M_A_CPU0_SA_CB<0>")
	)
	(arc
		(start 333.088742 -263.638792)
		(mid 332.995888 -263.600215)
		(end 332.89621 -263.586976)
		(width 0.088646)
		(layer "F.Cu")
		(net "M_A_CPU0_SA_CB<0>")
	)
	(segment
		(start 322.747132 -256.621026)
		(end 322.570348 -256.656078)
		(width 0.1016)
		(layer "F.Cu")
		(net "M_A_CPU0_SA_CA<6>")
	)
	(segment
		(start 304.356516 -261.508494)
		(end 304.37328 -261.49173)
		(width 0.101854)
		(layer "F.Cu")
		(net "M_A_CPU0_SA_CA<6>")
	)
	(segment
		(start 307.212746 -261.066788)
		(end 308.887114 -261.066788)
		(width 0.20066)
		(layer "F.Cu")
		(net "M_A_CPU0_SA_CA<6>")
	)
	(segment
		(start 303.48428 -261.967472)
		(end 303.78908 -261.967472)
		(width 0.20066)
		(layer "F.Cu")
		(net "M_A_CPU0_SA_CA<6>")
	)
	(segment
		(start 333.339694 -253.954026)
		(end 332.602586 -253.954026)
		(width 0.088646)
		(layer "F.Cu")
		(net "M_A_CPU0_SA_CA<6>")
	)
	(segment
		(start 321.835018 -256.985262)
		(end 317.07582 -258.956556)
		(width 0.20066)
		(layer "F.Cu")
		(net "M_A_CPU0_SA_CA<6>")
	)
	(segment
		(start 317.07582 -258.956556)
		(end 315.268356 -260.76402)
		(width 0.20066)
		(layer "F.Cu")
		(net "M_A_CPU0_SA_CA<6>")
	)
	(segment
		(start 304.026316 -261.508494)
		(end 304.319178 -261.508494)
		(width 0.20066)
		(layer "F.Cu")
		(net "M_A_CPU0_SA_CA<6>")
	)
	(segment
		(start 303.78908 -261.967472)
		(end 303.89068 -261.865872)
		(width 0.20066)
		(layer "F.Cu")
		(net "M_A_CPU0_SA_CA<6>")
	)
	(segment
		(start 314.9092 -260.912864)
		(end 314.315094 -261.50697)
		(width 0.20066)
		(layer "F.Cu")
		(net "M_A_CPU0_SA_CA<6>")
	)
	(segment
		(start 321.835272 -256.985262)
		(end 321.835018 -256.985262)
		(width 0.101854)
		(layer "F.Cu")
		(net "M_A_CPU0_SA_CA<6>")
	)
	(segment
		(start 314.15228 -261.50697)
		(end 314.150248 -261.50697)
		(width 0.101854)
		(layer "F.Cu")
		(net "M_A_CPU0_SA_CA<6>")
	)
	(segment
		(start 306.58308 -261.49173)
		(end 306.644294 -261.49173)
		(width 0.101854)
		(layer "F.Cu")
		(net "M_A_CPU0_SA_CA<6>")
	)
	(segment
		(start 321.90944 -256.92989)
		(end 321.847464 -256.955544)
		(width 0.1016)
		(layer "F.Cu")
		(net "M_A_CPU0_SA_CA<6>")
	)
	(segment
		(start 311.270904 -261.066788)
		(end 308.887114 -261.066788)
		(width 0.20066)
		(layer "F.Cu")
		(net "M_A_CPU0_SA_CA<6>")
	)
	(segment
		(start 315.268356 -260.76402)
		(end 314.9092 -260.912864)
		(width 0.20066)
		(layer "F.Cu")
		(net "M_A_CPU0_SA_CA<6>")
	)
	(segment
		(start 302.583596 -261.066788)
		(end 303.48428 -261.967472)
		(width 0.20066)
		(layer "F.Cu")
		(net "M_A_CPU0_SA_CA<6>")
	)
	(segment
		(start 314.135008 -261.49173)
		(end 311.941464 -261.49173)
		(width 0.1016)
		(layer "F.Cu")
		(net "M_A_CPU0_SA_CA<6>")
	)
	(segment
		(start 331.329538 -255.227074)
		(end 329.935586 -256.621026)
		(width 0.1016)
		(layer "F.Cu")
		(net "M_A_CPU0_SA_CA<6>")
	)
	(segment
		(start 332.602586 -253.954026)
		(end 331.329538 -255.227074)
		(width 0.088646)
		(layer "F.Cu")
		(net "M_A_CPU0_SA_CA<6>")
	)
	(segment
		(start 303.89068 -261.64413)
		(end 304.026316 -261.508494)
		(width 0.20066)
		(layer "F.Cu")
		(net "M_A_CPU0_SA_CA<6>")
	)
	(segment
		(start 314.150248 -261.50697)
		(end 314.135008 -261.49173)
		(width 0.101854)
		(layer "F.Cu")
		(net "M_A_CPU0_SA_CA<6>")
	)
	(segment
		(start 304.37328 -261.49173)
		(end 306.58308 -261.49173)
		(width 0.1016)
		(layer "F.Cu")
		(net "M_A_CPU0_SA_CA<6>")
	)
	(segment
		(start 311.707022 -261.502906)
		(end 311.270904 -261.066788)
		(width 0.20066)
		(layer "F.Cu")
		(net "M_A_CPU0_SA_CA<6>")
	)
	(segment
		(start 329.935586 -256.621026)
		(end 322.747132 -256.621026)
		(width 0.1016)
		(layer "F.Cu")
		(net "M_A_CPU0_SA_CA<6>")
	)
	(segment
		(start 304.319178 -261.508494)
		(end 304.356516 -261.508494)
		(width 0.101854)
		(layer "F.Cu")
		(net "M_A_CPU0_SA_CA<6>")
	)
	(segment
		(start 321.847464 -256.955544)
		(end 321.835272 -256.985262)
		(width 0.1016)
		(layer "F.Cu")
		(net "M_A_CPU0_SA_CA<6>")
	)
	(segment
		(start 306.644294 -261.49173)
		(end 306.787804 -261.49173)
		(width 0.20066)
		(layer "F.Cu")
		(net "M_A_CPU0_SA_CA<6>")
	)
	(segment
		(start 311.941464 -261.49173)
		(end 311.930288 -261.502906)
		(width 0.101854)
		(layer "F.Cu")
		(net "M_A_CPU0_SA_CA<6>")
	)
	(segment
		(start 314.315094 -261.50697)
		(end 314.15228 -261.50697)
		(width 0.20066)
		(layer "F.Cu")
		(net "M_A_CPU0_SA_CA<6>")
	)
	(segment
		(start 306.787804 -261.49173)
		(end 307.212746 -261.066788)
		(width 0.20066)
		(layer "F.Cu")
		(net "M_A_CPU0_SA_CA<6>")
	)
	(segment
		(start 311.91708 -261.502906)
		(end 311.707022 -261.502906)
		(width 0.20066)
		(layer "F.Cu")
		(net "M_A_CPU0_SA_CA<6>")
	)
	(segment
		(start 322.570348 -256.656078)
		(end 321.90944 -256.92989)
		(width 0.1016)
		(layer "F.Cu")
		(net "M_A_CPU0_SA_CA<6>")
	)
	(segment
		(start 333.845662 -254.197612)
		(end 333.339694 -253.954026)
		(width 0.088646)
		(layer "F.Cu")
		(net "M_A_CPU0_SA_CA<6>")
	)
	(segment
		(start 303.89068 -261.865872)
		(end 303.89068 -261.64413)
		(width 0.20066)
		(layer "F.Cu")
		(net "M_A_CPU0_SA_CA<6>")
	)
	(segment
		(start 301.343314 -261.066788)
		(end 302.583596 -261.066788)
		(width 0.20066)
		(layer "F.Cu")
		(net "M_A_CPU0_SA_CA<6>")
	)
	(segment
		(start 311.930288 -261.502906)
		(end 311.91708 -261.502906)
		(width 0.101854)
		(layer "F.Cu")
		(net "M_A_CPU0_SA_CA<6>")
	)
	(segment
		(start 332.030578 -254.957326)
		(end 331.545184 -255.44272)
		(width 0.088646)
		(layer "F.Cu")
		(net "M_A_CPU0_SA_CA<5>")
	)
	(segment
		(start 307.23332 -261.751572)
		(end 307.500782 -261.48411)
		(width 0.20066)
		(layer "F.Cu")
		(net "M_A_CPU0_SA_CA<5>")
	)
	(segment
		(start 310.01208 -261.49173)
		(end 310.088026 -261.49173)
		(width 0.101854)
		(layer "F.Cu")
		(net "M_A_CPU0_SA_CA<5>")
	)
	(segment
		(start 306.704238 -262.17499)
		(end 307.086762 -262.17499)
		(width 0.20066)
		(layer "F.Cu")
		(net "M_A_CPU0_SA_CA<5>")
	)
	(segment
		(start 311.30748 -261.916672)
		(end 312.987182 -261.916672)
		(width 0.20066)
		(layer "F.Cu")
		(net "M_A_CPU0_SA_CA<5>")
	)
	(segment
		(start 305.443382 -261.916672)
		(end 306.44592 -261.916672)
		(width 0.20066)
		(layer "F.Cu")
		(net "M_A_CPU0_SA_CA<5>")
	)
	(segment
		(start 322.904612 -256.925826)
		(end 322.755006 -256.987802)
		(width 0.1016)
		(layer "F.Cu")
		(net "M_A_CPU0_SA_CA<5>")
	)
	(segment
		(start 334.235806 -255.662938)
		(end 333.894684 -255.321816)
		(width 0.088646)
		(layer "F.Cu")
		(net "M_A_CPU0_SA_CA<5>")
	)
	(segment
		(start 334.623156 -255.662938)
		(end 334.235806 -255.662938)
		(width 0.088646)
		(layer "F.Cu")
		(net "M_A_CPU0_SA_CA<5>")
	)
	(segment
		(start 315.27242 -261.66445)
		(end 315.265816 -261.667244)
		(width 0.20066)
		(layer "F.Cu")
		(net "M_A_CPU0_SA_CA<5>")
	)
	(segment
		(start 315.265816 -261.667244)
		(end 314.663074 -261.916672)
		(width 0.20066)
		(layer "F.Cu")
		(net "M_A_CPU0_SA_CA<5>")
	)
	(segment
		(start 307.83657 -261.49173)
		(end 310.01208 -261.49173)
		(width 0.1016)
		(layer "F.Cu")
		(net "M_A_CPU0_SA_CA<5>")
	)
	(segment
		(start 307.76291 -261.48411)
		(end 307.82895 -261.48411)
		(width 0.101854)
		(layer "F.Cu")
		(net "M_A_CPU0_SA_CA<5>")
	)
	(segment
		(start 307.500782 -261.48411)
		(end 307.76291 -261.48411)
		(width 0.20066)
		(layer "F.Cu")
		(net "M_A_CPU0_SA_CA<5>")
	)
	(segment
		(start 310.882538 -261.49173)
		(end 311.30748 -261.916672)
		(width 0.20066)
		(layer "F.Cu")
		(net "M_A_CPU0_SA_CA<5>")
	)
	(segment
		(start 322.499228 -257.24358)
		(end 322.200524 -257.542284)
		(width 0.20066)
		(layer "F.Cu")
		(net "M_A_CPU0_SA_CA<5>")
	)
	(segment
		(start 310.088026 -261.49173)
		(end 310.882538 -261.49173)
		(width 0.20066)
		(layer "F.Cu")
		(net "M_A_CPU0_SA_CA<5>")
	)
	(segment
		(start 334.785716 -255.825498)
		(end 334.623156 -255.662938)
		(width 0.088646)
		(layer "F.Cu")
		(net "M_A_CPU0_SA_CA<5>")
	)
	(segment
		(start 322.755006 -256.987802)
		(end 322.499228 -257.24358)
		(width 0.1016)
		(layer "F.Cu")
		(net "M_A_CPU0_SA_CA<5>")
	)
	(segment
		(start 307.086762 -262.17499)
		(end 307.23332 -262.028432)
		(width 0.20066)
		(layer "F.Cu")
		(net "M_A_CPU0_SA_CA<5>")
	)
	(segment
		(start 307.82895 -261.48411)
		(end 307.83657 -261.49173)
		(width 0.101854)
		(layer "F.Cu")
		(net "M_A_CPU0_SA_CA<5>")
	)
	(segment
		(start 332.723998 -254.957326)
		(end 332.030578 -254.957326)
		(width 0.088646)
		(layer "F.Cu")
		(net "M_A_CPU0_SA_CA<5>")
	)
	(segment
		(start 307.23332 -262.028432)
		(end 307.23332 -261.751572)
		(width 0.20066)
		(layer "F.Cu")
		(net "M_A_CPU0_SA_CA<5>")
	)
	(segment
		(start 314.663074 -261.916672)
		(end 312.987182 -261.916672)
		(width 0.20066)
		(layer "F.Cu")
		(net "M_A_CPU0_SA_CA<5>")
	)
	(segment
		(start 333.894684 -255.321816)
		(end 333.594964 -255.304036)
		(width 0.088646)
		(layer "F.Cu")
		(net "M_A_CPU0_SA_CA<5>")
	)
	(segment
		(start 317.410846 -259.526024)
		(end 315.27242 -261.66445)
		(width 0.20066)
		(layer "F.Cu")
		(net "M_A_CPU0_SA_CA<5>")
	)
	(segment
		(start 330.062078 -256.925826)
		(end 322.904612 -256.925826)
		(width 0.1016)
		(layer "F.Cu")
		(net "M_A_CPU0_SA_CA<5>")
	)
	(segment
		(start 331.545184 -255.44272)
		(end 330.062078 -256.925826)
		(width 0.1016)
		(layer "F.Cu")
		(net "M_A_CPU0_SA_CA<5>")
	)
	(segment
		(start 333.594964 -255.304036)
		(end 333.56296 -255.33604)
		(width 0.088646)
		(layer "F.Cu")
		(net "M_A_CPU0_SA_CA<5>")
	)
	(segment
		(start 333.192374 -255.324356)
		(end 332.723998 -254.957326)
		(width 0.088646)
		(layer "F.Cu")
		(net "M_A_CPU0_SA_CA<5>")
	)
	(segment
		(start 306.44592 -261.916672)
		(end 306.704238 -262.17499)
		(width 0.20066)
		(layer "F.Cu")
		(net "M_A_CPU0_SA_CA<5>")
	)
	(segment
		(start 322.200524 -257.542284)
		(end 317.410846 -259.526024)
		(width 0.20066)
		(layer "F.Cu")
		(net "M_A_CPU0_SA_CA<5>")
	)
	(arc
		(start 333.56296 -255.33604)
		(mid 333.390384 -255.382186)
		(end 333.217774 -255.33604)
		(width 0.088646)
		(layer "F.Cu")
		(net "M_A_CPU0_SA_CA<5>")
	)
	(arc
		(start 333.217774 -255.33604)
		(mid 333.205395 -255.329498)
		(end 333.192374 -255.324356)
		(width 0.088646)
		(layer "F.Cu")
		(net "M_A_CPU0_SA_CA<5>")
	)
	(segment
		(start 333.49184 -255.730756)
		(end 332.891892 -255.385062)
		(width 0.088646)
		(layer "F.Cu")
		(net "M_A_CPU0_SA_CA<4>")
	)
	(segment
		(start 314.261246 -262.32358)
		(end 314.12688 -262.32358)
		(width 0.20066)
		(layer "F.Cu")
		(net "M_A_CPU0_SA_CA<4>")
	)
	(segment
		(start 311.91708 -262.326374)
		(end 310.247538 -262.326374)
		(width 0.20066)
		(layer "F.Cu")
		(net "M_A_CPU0_SA_CA<4>")
	)
	(segment
		(start 301.343314 -262.76681)
		(end 302.932338 -262.76681)
		(width 0.20066)
		(layer "F.Cu")
		(net "M_A_CPU0_SA_CA<4>")
	)
	(segment
		(start 303.144682 -262.979154)
		(end 303.144682 -263.212326)
		(width 0.20066)
		(layer "F.Cu")
		(net "M_A_CPU0_SA_CA<4>")
	)
	(segment
		(start 304.113438 -263.217914)
		(end 304.319178 -263.217914)
		(width 0.20066)
		(layer "F.Cu")
		(net "M_A_CPU0_SA_CA<4>")
	)
	(segment
		(start 315.265816 -262.40359)
		(end 314.877958 -262.564372)
		(width 0.20066)
		(layer "F.Cu")
		(net "M_A_CPU0_SA_CA<4>")
	)
	(segment
		(start 303.864264 -263.467088)
		(end 304.113438 -263.217914)
		(width 0.20066)
		(layer "F.Cu")
		(net "M_A_CPU0_SA_CA<4>")
	)
	(segment
		(start 315.559186 -262.282178)
		(end 315.265816 -262.40359)
		(width 0.20066)
		(layer "F.Cu")
		(net "M_A_CPU0_SA_CA<4>")
	)
	(segment
		(start 331.72273 -255.696466)
		(end 330.18857 -257.230626)
		(width 0.1016)
		(layer "F.Cu")
		(net "M_A_CPU0_SA_CA<4>")
	)
	(segment
		(start 323.096382 -257.567938)
		(end 323.093334 -257.570986)
		(width 0.1016)
		(layer "F.Cu")
		(net "M_A_CPU0_SA_CA<4>")
	)
	(segment
		(start 314.063126 -262.32358)
		(end 314.045092 -262.341614)
		(width 0.101854)
		(layer "F.Cu")
		(net "M_A_CPU0_SA_CA<4>")
	)
	(segment
		(start 314.12688 -262.32358)
		(end 314.063126 -262.32358)
		(width 0.101854)
		(layer "F.Cu")
		(net "M_A_CPU0_SA_CA<4>")
	)
	(segment
		(start 304.319178 -263.217914)
		(end 304.323496 -263.217914)
		(width 0.101854)
		(layer "F.Cu")
		(net "M_A_CPU0_SA_CA<4>")
	)
	(segment
		(start 332.253844 -255.165352)
		(end 331.72273 -255.696466)
		(width 0.088646)
		(layer "F.Cu")
		(net "M_A_CPU0_SA_CA<4>")
	)
	(segment
		(start 323.408548 -257.230626)
		(end 323.096382 -257.542792)
		(width 0.1016)
		(layer "F.Cu")
		(net "M_A_CPU0_SA_CA<4>")
	)
	(segment
		(start 332.891892 -255.385062)
		(end 332.791308 -255.284478)
		(width 0.088646)
		(layer "F.Cu")
		(net "M_A_CPU0_SA_CA<4>")
	)
	(segment
		(start 303.144682 -263.212326)
		(end 303.399444 -263.467088)
		(width 0.20066)
		(layer "F.Cu")
		(net "M_A_CPU0_SA_CA<4>")
	)
	(segment
		(start 314.045092 -262.341614)
		(end 311.959752 -262.341614)
		(width 0.1016)
		(layer "F.Cu")
		(net "M_A_CPU0_SA_CA<4>")
	)
	(segment
		(start 314.502038 -262.564372)
		(end 314.261246 -262.32358)
		(width 0.20066)
		(layer "F.Cu")
		(net "M_A_CPU0_SA_CA<4>")
	)
	(segment
		(start 322.591684 -258.072636)
		(end 317.77305 -260.068314)
		(width 0.20066)
		(layer "F.Cu")
		(net "M_A_CPU0_SA_CA<4>")
	)
	(segment
		(start 311.944512 -262.326374)
		(end 311.91708 -262.326374)
		(width 0.101854)
		(layer "F.Cu")
		(net "M_A_CPU0_SA_CA<4>")
	)
	(segment
		(start 323.096382 -257.542792)
		(end 323.096382 -257.567938)
		(width 0.1016)
		(layer "F.Cu")
		(net "M_A_CPU0_SA_CA<4>")
	)
	(segment
		(start 330.18857 -257.230626)
		(end 323.408548 -257.230626)
		(width 0.1016)
		(layer "F.Cu")
		(net "M_A_CPU0_SA_CA<4>")
	)
	(segment
		(start 307.306726 -262.766556)
		(end 307.30698 -262.76681)
		(width 0.20066)
		(layer "F.Cu")
		(net "M_A_CPU0_SA_CA<4>")
	)
	(segment
		(start 304.349658 -263.191752)
		(end 304.37328 -263.191752)
		(width 0.101854)
		(layer "F.Cu")
		(net "M_A_CPU0_SA_CA<4>")
	)
	(segment
		(start 304.37328 -263.191752)
		(end 306.60848 -263.191752)
		(width 0.1016)
		(layer "F.Cu")
		(net "M_A_CPU0_SA_CA<4>")
	)
	(segment
		(start 306.644294 -263.191752)
		(end 306.88153 -263.191752)
		(width 0.20066)
		(layer "F.Cu")
		(net "M_A_CPU0_SA_CA<4>")
	)
	(segment
		(start 311.959752 -262.341614)
		(end 311.944512 -262.326374)
		(width 0.101854)
		(layer "F.Cu")
		(net "M_A_CPU0_SA_CA<4>")
	)
	(segment
		(start 302.932338 -262.76681)
		(end 303.144682 -262.979154)
		(width 0.20066)
		(layer "F.Cu")
		(net "M_A_CPU0_SA_CA<4>")
	)
	(segment
		(start 306.88153 -263.191752)
		(end 307.306726 -262.766556)
		(width 0.20066)
		(layer "F.Cu")
		(net "M_A_CPU0_SA_CA<4>")
	)
	(segment
		(start 332.50378 -255.165352)
		(end 332.253844 -255.165352)
		(width 0.088646)
		(layer "F.Cu")
		(net "M_A_CPU0_SA_CA<4>")
	)
	(segment
		(start 323.093334 -257.570986)
		(end 322.591684 -258.072636)
		(width 0.20066)
		(layer "F.Cu")
		(net "M_A_CPU0_SA_CA<4>")
	)
	(segment
		(start 314.877958 -262.564372)
		(end 314.502038 -262.564372)
		(width 0.20066)
		(layer "F.Cu")
		(net "M_A_CPU0_SA_CA<4>")
	)
	(segment
		(start 306.60848 -263.191752)
		(end 306.644294 -263.191752)
		(width 0.101854)
		(layer "F.Cu")
		(net "M_A_CPU0_SA_CA<4>")
	)
	(segment
		(start 317.77305 -260.068314)
		(end 315.559186 -262.282178)
		(width 0.20066)
		(layer "F.Cu")
		(net "M_A_CPU0_SA_CA<4>")
	)
	(segment
		(start 310.247538 -262.326374)
		(end 309.807102 -262.76681)
		(width 0.20066)
		(layer "F.Cu")
		(net "M_A_CPU0_SA_CA<4>")
	)
	(segment
		(start 332.791308 -255.284478)
		(end 332.50378 -255.165352)
		(width 0.088646)
		(layer "F.Cu")
		(net "M_A_CPU0_SA_CA<4>")
	)
	(segment
		(start 304.323496 -263.217914)
		(end 304.349658 -263.191752)
		(width 0.101854)
		(layer "F.Cu")
		(net "M_A_CPU0_SA_CA<4>")
	)
	(segment
		(start 307.30698 -262.76681)
		(end 308.887114 -262.76681)
		(width 0.20066)
		(layer "F.Cu")
		(net "M_A_CPU0_SA_CA<4>")
	)
	(segment
		(start 309.807102 -262.76681)
		(end 308.887114 -262.76681)
		(width 0.20066)
		(layer "F.Cu")
		(net "M_A_CPU0_SA_CA<4>")
	)
	(segment
		(start 303.399444 -263.467088)
		(end 303.864264 -263.467088)
		(width 0.20066)
		(layer "F.Cu")
		(net "M_A_CPU0_SA_CA<4>")
	)
	(arc
		(start 333.845662 -255.825498)
		(mid 333.662533 -255.80136)
		(end 333.49184 -255.730756)
		(width 0.088646)
		(layer "F.Cu")
		(net "M_A_CPU0_SA_CA<4>")
	)
	(segment
		(start 332.249018 -256.456434)
		(end 331.394054 -256.456434)
		(width 0.1016)
		(layer "F.Cu")
		(net "M_A_CPU0_SA_CA<3>")
	)
	(segment
		(start 333.11084 -256.240026)
		(end 332.894432 -256.456434)
		(width 0.088646)
		(layer "F.Cu")
		(net "M_A_CPU0_SA_CA<3>")
	)
	(segment
		(start 322.855844 -258.754372)
		(end 318.192658 -260.686042)
		(width 0.20066)
		(layer "F.Cu")
		(net "M_A_CPU0_SA_CA<3>")
	)
	(segment
		(start 313.971686 -263.212072)
		(end 313.567064 -263.616694)
		(width 0.20066)
		(layer "F.Cu")
		(net "M_A_CPU0_SA_CA<3>")
	)
	(segment
		(start 323.915786 -257.69443)
		(end 323.691758 -257.918458)
		(width 0.1016)
		(layer "F.Cu")
		(net "M_A_CPU0_SA_CA<3>")
	)
	(segment
		(start 311.360058 -262.95223)
		(end 311.48782 -263.079992)
		(width 0.20066)
		(layer "F.Cu")
		(net "M_A_CPU0_SA_CA<3>")
	)
	(segment
		(start 310.460898 -263.191752)
		(end 310.70042 -262.95223)
		(width 0.20066)
		(layer "F.Cu")
		(net "M_A_CPU0_SA_CA<3>")
	)
	(segment
		(start 313.567064 -263.616694)
		(end 312.987182 -263.616694)
		(width 0.20066)
		(layer "F.Cu")
		(net "M_A_CPU0_SA_CA<3>")
	)
	(segment
		(start 314.762642 -263.530588)
		(end 314.444126 -263.212072)
		(width 0.20066)
		(layer "F.Cu")
		(net "M_A_CPU0_SA_CA<3>")
	)
	(segment
		(start 307.069744 -263.616694)
		(end 307.50891 -263.177528)
		(width 0.20066)
		(layer "F.Cu")
		(net "M_A_CPU0_SA_CA<3>")
	)
	(segment
		(start 315.348112 -263.530588)
		(end 314.762642 -263.530588)
		(width 0.20066)
		(layer "F.Cu")
		(net "M_A_CPU0_SA_CA<3>")
	)
	(segment
		(start 307.813456 -263.177528)
		(end 307.82768 -263.191752)
		(width 0.101854)
		(layer "F.Cu")
		(net "M_A_CPU0_SA_CA<3>")
	)
	(segment
		(start 324.29958 -257.535426)
		(end 323.915786 -257.69443)
		(width 0.1016)
		(layer "F.Cu")
		(net "M_A_CPU0_SA_CA<3>")
	)
	(segment
		(start 335.255362 -256.639314)
		(end 334.580484 -256.918968)
		(width 0.088646)
		(layer "F.Cu")
		(net "M_A_CPU0_SA_CA<3>")
	)
	(segment
		(start 311.760362 -263.616694)
		(end 312.987182 -263.616694)
		(width 0.20066)
		(layer "F.Cu")
		(net "M_A_CPU0_SA_CA<3>")
	)
	(segment
		(start 334.128618 -256.963672)
		(end 334.128364 -256.963672)
		(width 0.088646)
		(layer "F.Cu")
		(net "M_A_CPU0_SA_CA<3>")
	)
	(segment
		(start 333.913734 -256.433066)
		(end 333.720694 -256.240026)
		(width 0.088646)
		(layer "F.Cu")
		(net "M_A_CPU0_SA_CA<3>")
	)
	(segment
		(start 305.443382 -263.616694)
		(end 307.069744 -263.616694)
		(width 0.20066)
		(layer "F.Cu")
		(net "M_A_CPU0_SA_CA<3>")
	)
	(segment
		(start 310.088026 -263.191752)
		(end 310.460898 -263.191752)
		(width 0.20066)
		(layer "F.Cu")
		(net "M_A_CPU0_SA_CA<3>")
	)
	(segment
		(start 307.82768 -263.191752)
		(end 310.03748 -263.191752)
		(width 0.1016)
		(layer "F.Cu")
		(net "M_A_CPU0_SA_CA<3>")
	)
	(segment
		(start 310.03748 -263.191752)
		(end 310.088026 -263.191752)
		(width 0.101854)
		(layer "F.Cu")
		(net "M_A_CPU0_SA_CA<3>")
	)
	(segment
		(start 334.026764 -256.898902)
		(end 333.913734 -256.785872)
		(width 0.088646)
		(layer "F.Cu")
		(net "M_A_CPU0_SA_CA<3>")
	)
	(segment
		(start 307.50891 -263.177528)
		(end 307.76291 -263.177528)
		(width 0.20066)
		(layer "F.Cu")
		(net "M_A_CPU0_SA_CA<3>")
	)
	(segment
		(start 331.394054 -256.456434)
		(end 330.315062 -257.535426)
		(width 0.1016)
		(layer "F.Cu")
		(net "M_A_CPU0_SA_CA<3>")
	)
	(segment
		(start 333.720694 -256.240026)
		(end 333.11084 -256.240026)
		(width 0.088646)
		(layer "F.Cu")
		(net "M_A_CPU0_SA_CA<3>")
	)
	(segment
		(start 323.691758 -257.918458)
		(end 322.855844 -258.754372)
		(width 0.20066)
		(layer "F.Cu")
		(net "M_A_CPU0_SA_CA<3>")
	)
	(segment
		(start 318.192658 -260.686042)
		(end 315.348112 -263.530588)
		(width 0.20066)
		(layer "F.Cu")
		(net "M_A_CPU0_SA_CA<3>")
	)
	(segment
		(start 334.580484 -256.918968)
		(end 334.50276 -256.963672)
		(width 0.088646)
		(layer "F.Cu")
		(net "M_A_CPU0_SA_CA<3>")
	)
	(segment
		(start 310.70042 -262.95223)
		(end 311.360058 -262.95223)
		(width 0.20066)
		(layer "F.Cu")
		(net "M_A_CPU0_SA_CA<3>")
	)
	(segment
		(start 332.894432 -256.456434)
		(end 332.249018 -256.456434)
		(width 0.088646)
		(layer "F.Cu")
		(net "M_A_CPU0_SA_CA<3>")
	)
	(segment
		(start 314.444126 -263.212072)
		(end 313.971686 -263.212072)
		(width 0.20066)
		(layer "F.Cu")
		(net "M_A_CPU0_SA_CA<3>")
	)
	(segment
		(start 311.48782 -263.344152)
		(end 311.760362 -263.616694)
		(width 0.20066)
		(layer "F.Cu")
		(net "M_A_CPU0_SA_CA<3>")
	)
	(segment
		(start 307.76291 -263.177528)
		(end 307.813456 -263.177528)
		(width 0.101854)
		(layer "F.Cu")
		(net "M_A_CPU0_SA_CA<3>")
	)
	(segment
		(start 330.315062 -257.535426)
		(end 324.29958 -257.535426)
		(width 0.1016)
		(layer "F.Cu")
		(net "M_A_CPU0_SA_CA<3>")
	)
	(segment
		(start 333.913734 -256.785872)
		(end 333.913734 -256.433066)
		(width 0.088646)
		(layer "F.Cu")
		(net "M_A_CPU0_SA_CA<3>")
	)
	(segment
		(start 311.48782 -263.079992)
		(end 311.48782 -263.344152)
		(width 0.20066)
		(layer "F.Cu")
		(net "M_A_CPU0_SA_CA<3>")
	)
	(arc
		(start 334.50276 -256.963672)
		(mid 334.315706 -257.013756)
		(end 334.128618 -256.963672)
		(width 0.088646)
		(layer "F.Cu")
		(net "M_A_CPU0_SA_CA<3>")
	)
	(arc
		(start 334.128364 -256.963672)
		(mid 334.076846 -256.932413)
		(end 334.026764 -256.898902)
		(width 0.088646)
		(layer "F.Cu")
		(net "M_A_CPU0_SA_CA<3>")
	)
	(segment
		(start 303.181512 -265.138916)
		(end 303.614836 -265.138916)
		(width 0.20066)
		(layer "F.Cu")
		(net "M_A_CPU0_SA_CA<2>")
	)
	(segment
		(start 333.090774 -256.639314)
		(end 333.375762 -256.639314)
		(width 0.088646)
		(layer "F.Cu")
		(net "M_A_CPU0_SA_CA<2>")
	)
	(segment
		(start 308.887114 -264.466578)
		(end 309.953914 -264.466578)
		(width 0.20066)
		(layer "F.Cu")
		(net "M_A_CPU0_SA_CA<2>")
	)
	(segment
		(start 303.614836 -265.138916)
		(end 303.84623 -264.907522)
		(width 0.20066)
		(layer "F.Cu")
		(net "M_A_CPU0_SA_CA<2>")
	)
	(segment
		(start 315.613034 -264.17016)
		(end 318.554354 -261.22884)
		(width 0.20066)
		(layer "F.Cu")
		(net "M_A_CPU0_SA_CA<2>")
	)
	(segment
		(start 332.325218 -256.766314)
		(end 332.963774 -256.766314)
		(width 0.088646)
		(layer "F.Cu")
		(net "M_A_CPU0_SA_CA<2>")
	)
	(segment
		(start 310.392826 -264.027666)
		(end 311.91708 -264.027666)
		(width 0.20066)
		(layer "F.Cu")
		(net "M_A_CPU0_SA_CA<2>")
	)
	(segment
		(start 324.715886 -258.011676)
		(end 324.887336 -257.840226)
		(width 0.1016)
		(layer "F.Cu")
		(net "M_A_CPU0_SA_CA<2>")
	)
	(segment
		(start 314.131198 -264.027666)
		(end 314.15228 -264.027666)
		(width 0.101854)
		(layer "F.Cu")
		(net "M_A_CPU0_SA_CA<2>")
	)
	(segment
		(start 307.30698 -264.466578)
		(end 308.887114 -264.466578)
		(width 0.20066)
		(layer "F.Cu")
		(net "M_A_CPU0_SA_CA<2>")
	)
	(segment
		(start 304.37328 -264.89152)
		(end 306.60848 -264.89152)
		(width 0.1016)
		(layer "F.Cu")
		(net "M_A_CPU0_SA_CA<2>")
	)
	(segment
		(start 318.814958 -261.120636)
		(end 323.581522 -259.14604)
		(width 0.20066)
		(layer "F.Cu")
		(net "M_A_CPU0_SA_CA<2>")
	)
	(segment
		(start 306.644294 -264.89152)
		(end 306.88153 -264.89152)
		(width 0.20066)
		(layer "F.Cu")
		(net "M_A_CPU0_SA_CA<2>")
	)
	(segment
		(start 314.15228 -264.027666)
		(end 314.409074 -264.027666)
		(width 0.20066)
		(layer "F.Cu")
		(net "M_A_CPU0_SA_CA<2>")
	)
	(segment
		(start 311.91708 -264.027666)
		(end 311.941718 -264.027666)
		(width 0.101854)
		(layer "F.Cu")
		(net "M_A_CPU0_SA_CA<2>")
	)
	(segment
		(start 303.02708 -264.71245)
		(end 303.02708 -264.984484)
		(width 0.20066)
		(layer "F.Cu")
		(net "M_A_CPU0_SA_CA<2>")
	)
	(segment
		(start 311.955688 -264.041636)
		(end 314.117228 -264.041636)
		(width 0.1016)
		(layer "F.Cu")
		(net "M_A_CPU0_SA_CA<2>")
	)
	(segment
		(start 309.953914 -264.466578)
		(end 310.392826 -264.027666)
		(width 0.20066)
		(layer "F.Cu")
		(net "M_A_CPU0_SA_CA<2>")
	)
	(segment
		(start 301.343314 -264.466578)
		(end 302.781208 -264.466578)
		(width 0.20066)
		(layer "F.Cu")
		(net "M_A_CPU0_SA_CA<2>")
	)
	(segment
		(start 318.81445 -261.121144)
		(end 318.814958 -261.120636)
		(width 0.20066)
		(layer "F.Cu")
		(net "M_A_CPU0_SA_CA<2>")
	)
	(segment
		(start 302.781208 -264.466578)
		(end 303.02708 -264.71245)
		(width 0.20066)
		(layer "F.Cu")
		(net "M_A_CPU0_SA_CA<2>")
	)
	(segment
		(start 304.319178 -264.907522)
		(end 304.333656 -264.907522)
		(width 0.101854)
		(layer "F.Cu")
		(net "M_A_CPU0_SA_CA<2>")
	)
	(segment
		(start 304.333656 -264.907522)
		(end 304.349658 -264.89152)
		(width 0.101854)
		(layer "F.Cu")
		(net "M_A_CPU0_SA_CA<2>")
	)
	(segment
		(start 324.887336 -257.840226)
		(end 330.441554 -257.840226)
		(width 0.1016)
		(layer "F.Cu")
		(net "M_A_CPU0_SA_CA<2>")
	)
	(segment
		(start 314.409074 -264.027666)
		(end 314.551568 -264.17016)
		(width 0.20066)
		(layer "F.Cu")
		(net "M_A_CPU0_SA_CA<2>")
	)
	(segment
		(start 314.551568 -264.17016)
		(end 315.613034 -264.17016)
		(width 0.20066)
		(layer "F.Cu")
		(net "M_A_CPU0_SA_CA<2>")
	)
	(segment
		(start 323.581522 -259.14604)
		(end 324.715886 -258.011676)
		(width 0.20066)
		(layer "F.Cu")
		(net "M_A_CPU0_SA_CA<2>")
	)
	(segment
		(start 303.84623 -264.907522)
		(end 304.319178 -264.907522)
		(width 0.20066)
		(layer "F.Cu")
		(net "M_A_CPU0_SA_CA<2>")
	)
	(segment
		(start 314.117228 -264.041636)
		(end 314.131198 -264.027666)
		(width 0.101854)
		(layer "F.Cu")
		(net "M_A_CPU0_SA_CA<2>")
	)
	(segment
		(start 304.349658 -264.89152)
		(end 304.37328 -264.89152)
		(width 0.101854)
		(layer "F.Cu")
		(net "M_A_CPU0_SA_CA<2>")
	)
	(segment
		(start 318.554354 -261.22884)
		(end 318.81445 -261.121144)
		(width 0.20066)
		(layer "F.Cu")
		(net "M_A_CPU0_SA_CA<2>")
	)
	(segment
		(start 307.306726 -264.466324)
		(end 307.30698 -264.466578)
		(width 0.20066)
		(layer "F.Cu")
		(net "M_A_CPU0_SA_CA<2>")
	)
	(segment
		(start 332.963774 -256.766314)
		(end 333.090774 -256.639314)
		(width 0.088646)
		(layer "F.Cu")
		(net "M_A_CPU0_SA_CA<2>")
	)
	(segment
		(start 311.941718 -264.027666)
		(end 311.955688 -264.041636)
		(width 0.101854)
		(layer "F.Cu")
		(net "M_A_CPU0_SA_CA<2>")
	)
	(segment
		(start 330.441554 -257.840226)
		(end 331.515466 -256.766314)
		(width 0.1016)
		(layer "F.Cu")
		(net "M_A_CPU0_SA_CA<2>")
	)
	(segment
		(start 303.02708 -264.984484)
		(end 303.181512 -265.138916)
		(width 0.20066)
		(layer "F.Cu")
		(net "M_A_CPU0_SA_CA<2>")
	)
	(segment
		(start 306.60848 -264.89152)
		(end 306.644294 -264.89152)
		(width 0.101854)
		(layer "F.Cu")
		(net "M_A_CPU0_SA_CA<2>")
	)
	(segment
		(start 331.515466 -256.766314)
		(end 332.325218 -256.766314)
		(width 0.1016)
		(layer "F.Cu")
		(net "M_A_CPU0_SA_CA<2>")
	)
	(segment
		(start 306.88153 -264.89152)
		(end 307.306726 -264.466324)
		(width 0.20066)
		(layer "F.Cu")
		(net "M_A_CPU0_SA_CA<2>")
	)
	(segment
		(start 332.906116 -257.078734)
		(end 332.643226 -257.078734)
		(width 0.088646)
		(layer "F.Cu")
		(net "M_A_CPU0_SA_CA<1>")
	)
	(segment
		(start 307.76291 -264.873232)
		(end 307.796438 -264.873232)
		(width 0.101854)
		(layer "F.Cu")
		(net "M_A_CPU0_SA_CA<1>")
	)
	(segment
		(start 334.043274 -257.134868)
		(end 334.03286 -257.128772)
		(width 0.088646)
		(layer "F.Cu")
		(net "M_A_CPU0_SA_CA<1>")
	)
	(segment
		(start 330.568046 -258.145026)
		(end 325.584312 -258.145026)
		(width 0.1016)
		(layer "F.Cu")
		(net "M_A_CPU0_SA_CA<1>")
	)
	(segment
		(start 318.916304 -261.771384)
		(end 315.877956 -264.809732)
		(width 0.20066)
		(layer "F.Cu")
		(net "M_A_CPU0_SA_CA<1>")
	)
	(segment
		(start 324.109842 -259.619496)
		(end 319.177416 -261.662926)
		(width 0.20066)
		(layer "F.Cu")
		(net "M_A_CPU0_SA_CA<1>")
	)
	(segment
		(start 310.205628 -264.89152)
		(end 310.515254 -265.201146)
		(width 0.20066)
		(layer "F.Cu")
		(net "M_A_CPU0_SA_CA<1>")
	)
	(segment
		(start 325.292974 -258.436364)
		(end 324.109842 -259.619496)
		(width 0.20066)
		(layer "F.Cu")
		(net "M_A_CPU0_SA_CA<1>")
	)
	(segment
		(start 313.72556 -265.142472)
		(end 313.551316 -265.316716)
		(width 0.20066)
		(layer "F.Cu")
		(net "M_A_CPU0_SA_CA<1>")
	)
	(segment
		(start 311.27065 -264.772394)
		(end 311.529222 -264.772394)
		(width 0.20066)
		(layer "F.Cu")
		(net "M_A_CPU0_SA_CA<1>")
	)
	(segment
		(start 307.513228 -264.873232)
		(end 307.76291 -264.873232)
		(width 0.20066)
		(layer "F.Cu")
		(net "M_A_CPU0_SA_CA<1>")
	)
	(segment
		(start 310.841898 -265.201146)
		(end 311.27065 -264.772394)
		(width 0.20066)
		(layer "F.Cu")
		(net "M_A_CPU0_SA_CA<1>")
	)
	(segment
		(start 314.049156 -265.142472)
		(end 313.72556 -265.142472)
		(width 0.20066)
		(layer "F.Cu")
		(net "M_A_CPU0_SA_CA<1>")
	)
	(segment
		(start 325.584312 -258.145026)
		(end 325.292974 -258.436364)
		(width 0.1016)
		(layer "F.Cu")
		(net "M_A_CPU0_SA_CA<1>")
	)
	(segment
		(start 310.088026 -264.89152)
		(end 310.205628 -264.89152)
		(width 0.20066)
		(layer "F.Cu")
		(net "M_A_CPU0_SA_CA<1>")
	)
	(segment
		(start 305.443382 -265.316716)
		(end 307.069744 -265.316716)
		(width 0.20066)
		(layer "F.Cu")
		(net "M_A_CPU0_SA_CA<1>")
	)
	(segment
		(start 307.796438 -264.873232)
		(end 307.814726 -264.89152)
		(width 0.101854)
		(layer "F.Cu")
		(net "M_A_CPU0_SA_CA<1>")
	)
	(segment
		(start 319.176908 -261.663434)
		(end 318.916304 -261.771384)
		(width 0.20066)
		(layer "F.Cu")
		(net "M_A_CPU0_SA_CA<1>")
	)
	(segment
		(start 313.551316 -265.316716)
		(end 312.987182 -265.316716)
		(width 0.20066)
		(layer "F.Cu")
		(net "M_A_CPU0_SA_CA<1>")
	)
	(segment
		(start 319.177416 -261.662926)
		(end 319.176908 -261.663434)
		(width 0.20066)
		(layer "F.Cu")
		(net "M_A_CPU0_SA_CA<1>")
	)
	(segment
		(start 312.073544 -265.316716)
		(end 312.987182 -265.316716)
		(width 0.20066)
		(layer "F.Cu")
		(net "M_A_CPU0_SA_CA<1>")
	)
	(segment
		(start 307.814726 -264.89152)
		(end 310.076342 -264.89152)
		(width 0.1016)
		(layer "F.Cu")
		(net "M_A_CPU0_SA_CA<1>")
	)
	(segment
		(start 310.076342 -264.89152)
		(end 310.088026 -264.89152)
		(width 0.101854)
		(layer "F.Cu")
		(net "M_A_CPU0_SA_CA<1>")
	)
	(segment
		(start 331.634338 -257.078734)
		(end 330.568046 -258.145026)
		(width 0.1016)
		(layer "F.Cu")
		(net "M_A_CPU0_SA_CA<1>")
	)
	(segment
		(start 311.529222 -264.772394)
		(end 312.073544 -265.316716)
		(width 0.20066)
		(layer "F.Cu")
		(net "M_A_CPU0_SA_CA<1>")
	)
	(segment
		(start 335.725262 -257.45313)
		(end 335.35493 -257.082798)
		(width 0.088646)
		(layer "F.Cu")
		(net "M_A_CPU0_SA_CA<1>")
	)
	(segment
		(start 307.069744 -265.316716)
		(end 307.513228 -264.873232)
		(width 0.20066)
		(layer "F.Cu")
		(net "M_A_CPU0_SA_CA<1>")
	)
	(segment
		(start 335.35493 -257.082798)
		(end 334.841342 -257.082798)
		(width 0.088646)
		(layer "F.Cu")
		(net "M_A_CPU0_SA_CA<1>")
	)
	(segment
		(start 310.515254 -265.201146)
		(end 310.841898 -265.201146)
		(width 0.20066)
		(layer "F.Cu")
		(net "M_A_CPU0_SA_CA<1>")
	)
	(segment
		(start 315.877956 -264.809732)
		(end 314.381896 -264.809732)
		(width 0.20066)
		(layer "F.Cu")
		(net "M_A_CPU0_SA_CA<1>")
	)
	(segment
		(start 332.643226 -257.078734)
		(end 331.634338 -257.078734)
		(width 0.1016)
		(layer "F.Cu")
		(net "M_A_CPU0_SA_CA<1>")
	)
	(segment
		(start 333.103728 -257.134868)
		(end 333.093314 -257.128772)
		(width 0.088646)
		(layer "F.Cu")
		(net "M_A_CPU0_SA_CA<1>")
	)
	(segment
		(start 314.381896 -264.809732)
		(end 314.049156 -265.142472)
		(width 0.20066)
		(layer "F.Cu")
		(net "M_A_CPU0_SA_CA<1>")
	)
	(arc
		(start 333.658464 -257.128772)
		(mid 333.381905 -257.204515)
		(end 333.103728 -257.134868)
		(width 0.088646)
		(layer "F.Cu")
		(net "M_A_CPU0_SA_CA<1>")
	)
	(arc
		(start 334.03286 -257.128772)
		(mid 333.845662 -257.078629)
		(end 333.658464 -257.128772)
		(width 0.088646)
		(layer "F.Cu")
		(net "M_A_CPU0_SA_CA<1>")
	)
	(arc
		(start 334.598518 -257.128772)
		(mid 334.321705 -257.204642)
		(end 334.043274 -257.134868)
		(width 0.088646)
		(layer "F.Cu")
		(net "M_A_CPU0_SA_CA<1>")
	)
	(arc
		(start 334.841342 -257.082798)
		(mid 334.716031 -257.085184)
		(end 334.598518 -257.128772)
		(width 0.088646)
		(layer "F.Cu")
		(net "M_A_CPU0_SA_CA<1>")
	)
	(arc
		(start 333.093314 -257.128772)
		(mid 333.003007 -257.091443)
		(end 332.906116 -257.078734)
		(width 0.088646)
		(layer "F.Cu")
		(net "M_A_CPU0_SA_CA<1>")
	)
	(segment
		(start 315.806582 -265.579606)
		(end 316.158118 -265.434064)
		(width 0.20066)
		(layer "F.Cu")
		(net "M_A_CPU0_SA_CA<0>")
	)
	(segment
		(start 324.47611 -260.160262)
		(end 326.013064 -258.623308)
		(width 0.20066)
		(layer "F.Cu")
		(net "M_A_CPU0_SA_CA<0>")
	)
	(segment
		(start 314.113672 -265.741658)
		(end 314.13958 -265.71575)
		(width 0.101854)
		(layer "F.Cu")
		(net "M_A_CPU0_SA_CA<0>")
	)
	(segment
		(start 304.319178 -265.697208)
		(end 304.367184 -265.697208)
		(width 0.101854)
		(layer "F.Cu")
		(net "M_A_CPU0_SA_CA<0>")
	)
	(segment
		(start 301.343314 -266.1666)
		(end 302.633888 -266.1666)
		(width 0.20066)
		(layer "F.Cu")
		(net "M_A_CPU0_SA_CA<0>")
	)
	(segment
		(start 302.958246 -266.490958)
		(end 303.354994 -266.490958)
		(width 0.20066)
		(layer "F.Cu")
		(net "M_A_CPU0_SA_CA<0>")
	)
	(segment
		(start 303.354994 -266.490958)
		(end 303.83988 -266.006072)
		(width 0.20066)
		(layer "F.Cu")
		(net "M_A_CPU0_SA_CA<0>")
	)
	(segment
		(start 311.91708 -265.723878)
		(end 311.94756 -265.723878)
		(width 0.101854)
		(layer "F.Cu")
		(net "M_A_CPU0_SA_CA<0>")
	)
	(segment
		(start 306.60848 -265.741658)
		(end 306.644294 -265.741658)
		(width 0.101854)
		(layer "F.Cu")
		(net "M_A_CPU0_SA_CA<0>")
	)
	(segment
		(start 310.52897 -265.723878)
		(end 311.91708 -265.723878)
		(width 0.20066)
		(layer "F.Cu")
		(net "M_A_CPU0_SA_CA<0>")
	)
	(segment
		(start 307.65242 -265.741658)
		(end 308.077362 -266.1666)
		(width 0.20066)
		(layer "F.Cu")
		(net "M_A_CPU0_SA_CA<0>")
	)
	(segment
		(start 304.01133 -265.697208)
		(end 304.319178 -265.697208)
		(width 0.20066)
		(layer "F.Cu")
		(net "M_A_CPU0_SA_CA<0>")
	)
	(segment
		(start 319.53962 -262.205216)
		(end 324.10781 -260.31317)
		(width 0.20066)
		(layer "F.Cu")
		(net "M_A_CPU0_SA_CA<0>")
	)
	(segment
		(start 310.086248 -266.1666)
		(end 310.52897 -265.723878)
		(width 0.20066)
		(layer "F.Cu")
		(net "M_A_CPU0_SA_CA<0>")
	)
	(segment
		(start 314.473336 -265.579606)
		(end 315.806582 -265.579606)
		(width 0.20066)
		(layer "F.Cu")
		(net "M_A_CPU0_SA_CA<0>")
	)
	(segment
		(start 316.158118 -265.434064)
		(end 319.278508 -262.313674)
		(width 0.20066)
		(layer "F.Cu")
		(net "M_A_CPU0_SA_CA<0>")
	)
	(segment
		(start 302.633888 -266.1666)
		(end 302.958246 -266.490958)
		(width 0.20066)
		(layer "F.Cu")
		(net "M_A_CPU0_SA_CA<0>")
	)
	(segment
		(start 330.694538 -258.449826)
		(end 331.691234 -257.45313)
		(width 0.1016)
		(layer "F.Cu")
		(net "M_A_CPU0_SA_CA<0>")
	)
	(segment
		(start 304.411634 -265.741658)
		(end 306.60848 -265.741658)
		(width 0.1016)
		(layer "F.Cu")
		(net "M_A_CPU0_SA_CA<0>")
	)
	(segment
		(start 303.83988 -265.868658)
		(end 304.01133 -265.697208)
		(width 0.20066)
		(layer "F.Cu")
		(net "M_A_CPU0_SA_CA<0>")
	)
	(segment
		(start 326.013064 -258.623308)
		(end 326.186546 -258.449826)
		(width 0.1016)
		(layer "F.Cu")
		(net "M_A_CPU0_SA_CA<0>")
	)
	(segment
		(start 319.539112 -262.205724)
		(end 319.53962 -262.205216)
		(width 0.20066)
		(layer "F.Cu")
		(net "M_A_CPU0_SA_CA<0>")
	)
	(segment
		(start 324.10781 -260.31317)
		(end 324.108064 -260.312662)
		(width 0.20066)
		(layer "F.Cu")
		(net "M_A_CPU0_SA_CA<0>")
	)
	(segment
		(start 314.13958 -265.71575)
		(end 314.15228 -265.71575)
		(width 0.101854)
		(layer "F.Cu")
		(net "M_A_CPU0_SA_CA<0>")
	)
	(segment
		(start 331.691234 -257.45313)
		(end 332.906116 -257.45313)
		(width 0.1016)
		(layer "F.Cu")
		(net "M_A_CPU0_SA_CA<0>")
	)
	(segment
		(start 324.108064 -260.312662)
		(end 324.47611 -260.160262)
		(width 0.20066)
		(layer "F.Cu")
		(net "M_A_CPU0_SA_CA<0>")
	)
	(segment
		(start 304.367184 -265.697208)
		(end 304.411634 -265.741658)
		(width 0.101854)
		(layer "F.Cu")
		(net "M_A_CPU0_SA_CA<0>")
	)
	(segment
		(start 306.644294 -265.741658)
		(end 307.65242 -265.741658)
		(width 0.20066)
		(layer "F.Cu")
		(net "M_A_CPU0_SA_CA<0>")
	)
	(segment
		(start 314.15228 -265.71575)
		(end 314.337192 -265.71575)
		(width 0.20066)
		(layer "F.Cu")
		(net "M_A_CPU0_SA_CA<0>")
	)
	(segment
		(start 326.186546 -258.449826)
		(end 330.694538 -258.449826)
		(width 0.1016)
		(layer "F.Cu")
		(net "M_A_CPU0_SA_CA<0>")
	)
	(segment
		(start 314.337192 -265.71575)
		(end 314.473336 -265.579606)
		(width 0.20066)
		(layer "F.Cu")
		(net "M_A_CPU0_SA_CA<0>")
	)
	(segment
		(start 308.077362 -266.1666)
		(end 308.887114 -266.1666)
		(width 0.20066)
		(layer "F.Cu")
		(net "M_A_CPU0_SA_CA<0>")
	)
	(segment
		(start 311.94756 -265.723878)
		(end 311.96534 -265.741658)
		(width 0.101854)
		(layer "F.Cu")
		(net "M_A_CPU0_SA_CA<0>")
	)
	(segment
		(start 308.887114 -266.1666)
		(end 310.086248 -266.1666)
		(width 0.20066)
		(layer "F.Cu")
		(net "M_A_CPU0_SA_CA<0>")
	)
	(segment
		(start 311.96534 -265.741658)
		(end 314.113672 -265.741658)
		(width 0.1016)
		(layer "F.Cu")
		(net "M_A_CPU0_SA_CA<0>")
	)
	(segment
		(start 319.278508 -262.313674)
		(end 319.539112 -262.205724)
		(width 0.20066)
		(layer "F.Cu")
		(net "M_A_CPU0_SA_CA<0>")
	)
	(segment
		(start 303.83988 -266.006072)
		(end 303.83988 -265.868658)
		(width 0.20066)
		(layer "F.Cu")
		(net "M_A_CPU0_SA_CA<0>")
	)
	(segment
		(start 320.086736 -256.150364)
		(end 319.924176 -256.083054)
		(width 0.20066)
		(layer "F.Cu")
		(net "M_A_CPU0_CLK_DP<1>")
	)
	(segment
		(start 331.04074 -251.978668)
		(end 330.352908 -253.007876)
		(width 0.20066)
		(layer "F.Cu")
		(net "M_A_CPU0_CLK_DP<1>")
	)
	(segment
		(start 314.160916 -259.988812)
		(end 313.77128 -259.988812)
		(width 0.20066)
		(layer "F.Cu")
		(net "M_A_CPU0_CLK_DP<1>")
	)
	(segment
		(start 331.946758 -251.420376)
		(end 331.918818 -251.420376)
		(width 0.088646)
		(layer "F.Cu")
		(net "M_A_CPU0_CLK_DP<1>")
	)
	(segment
		(start 332.015592 -251.351542)
		(end 331.946758 -251.420376)
		(width 0.088646)
		(layer "F.Cu")
		(net "M_A_CPU0_CLK_DP<1>")
	)
	(segment
		(start 317.95847 -257.032252)
		(end 317.401956 -257.262884)
		(width 0.20066)
		(layer "F.Cu")
		(net "M_A_CPU0_CLK_DP<1>")
	)
	(segment
		(start 334.20177 -250.864878)
		(end 333.715106 -251.351542)
		(width 0.088646)
		(layer "F.Cu")
		(net "M_A_CPU0_CLK_DP<1>")
	)
	(segment
		(start 319.30086 -256.475992)
		(end 318.744346 -256.706624)
		(width 0.20066)
		(layer "F.Cu")
		(net "M_A_CPU0_CLK_DP<1>")
	)
	(segment
		(start 334.488536 -249.831606)
		(end 334.479646 -249.836686)
		(width 0.088646)
		(layer "F.Cu")
		(net "M_A_CPU0_CLK_DP<1>")
	)
	(segment
		(start 320.71056 -255.757172)
		(end 320.64325 -255.919732)
		(width 0.20066)
		(layer "F.Cu")
		(net "M_A_CPU0_CLK_DP<1>")
	)
	(segment
		(start 318.02578 -256.869438)
		(end 317.95847 -257.032252)
		(width 0.20066)
		(layer "F.Cu")
		(net "M_A_CPU0_CLK_DP<1>")
	)
	(segment
		(start 334.301084 -250.625102)
		(end 334.20177 -250.864878)
		(width 0.088646)
		(layer "F.Cu")
		(net "M_A_CPU0_CLK_DP<1>")
	)
	(segment
		(start 334.864456 -249.832368)
		(end 334.862932 -249.831606)
		(width 0.088646)
		(layer "F.Cu")
		(net "M_A_CPU0_CLK_DP<1>")
	)
	(segment
		(start 319.36817 -256.313432)
		(end 319.30086 -256.475992)
		(width 0.20066)
		(layer "F.Cu")
		(net "M_A_CPU0_CLK_DP<1>")
	)
	(segment
		(start 317.401956 -257.262884)
		(end 317.239396 -257.19532)
		(width 0.20066)
		(layer "F.Cu")
		(net "M_A_CPU0_CLK_DP<1>")
	)
	(segment
		(start 321.102228 -255.594866)
		(end 320.71056 -255.757172)
		(width 0.20066)
		(layer "F.Cu")
		(net "M_A_CPU0_CLK_DP<1>")
	)
	(segment
		(start 313.543442 -260.21665)
		(end 312.987182 -260.21665)
		(width 0.20066)
		(layer "F.Cu")
		(net "M_A_CPU0_CLK_DP<1>")
	)
	(segment
		(start 319.924176 -256.083054)
		(end 319.36817 -256.313432)
		(width 0.20066)
		(layer "F.Cu")
		(net "M_A_CPU0_CLK_DP<1>")
	)
	(segment
		(start 334.675734 -250.155964)
		(end 334.98663 -250.155964)
		(width 0.088646)
		(layer "F.Cu")
		(net "M_A_CPU0_CLK_DP<1>")
	)
	(segment
		(start 316.752986 -257.396742)
		(end 314.160916 -259.988812)
		(width 0.20066)
		(layer "F.Cu")
		(net "M_A_CPU0_CLK_DP<1>")
	)
	(segment
		(start 320.64325 -255.919732)
		(end 320.086736 -256.150364)
		(width 0.20066)
		(layer "F.Cu")
		(net "M_A_CPU0_CLK_DP<1>")
	)
	(segment
		(start 327.765918 -255.594866)
		(end 321.102228 -255.594866)
		(width 0.20066)
		(layer "F.Cu")
		(net "M_A_CPU0_CLK_DP<1>")
	)
	(segment
		(start 318.744346 -256.706624)
		(end 318.581786 -256.639314)
		(width 0.20066)
		(layer "F.Cu")
		(net "M_A_CPU0_CLK_DP<1>")
	)
	(segment
		(start 318.581786 -256.639314)
		(end 318.02578 -256.869438)
		(width 0.20066)
		(layer "F.Cu")
		(net "M_A_CPU0_CLK_DP<1>")
	)
	(segment
		(start 317.239396 -257.19532)
		(end 316.752986 -257.396742)
		(width 0.20066)
		(layer "F.Cu")
		(net "M_A_CPU0_CLK_DP<1>")
	)
	(segment
		(start 331.598778 -251.420376)
		(end 331.04074 -251.978668)
		(width 0.20066)
		(layer "F.Cu")
		(net "M_A_CPU0_CLK_DP<1>")
	)
	(segment
		(start 334.98663 -250.155964)
		(end 335.045558 -250.097036)
		(width 0.088646)
		(layer "F.Cu")
		(net "M_A_CPU0_CLK_DP<1>")
	)
	(segment
		(start 334.301084 -250.155964)
		(end 334.301084 -250.625102)
		(width 0.088646)
		(layer "F.Cu")
		(net "M_A_CPU0_CLK_DP<1>")
	)
	(segment
		(start 330.352908 -253.007876)
		(end 327.765918 -255.594866)
		(width 0.20066)
		(layer "F.Cu")
		(net "M_A_CPU0_CLK_DP<1>")
	)
	(segment
		(start 313.77128 -259.988812)
		(end 313.543442 -260.21665)
		(width 0.20066)
		(layer "F.Cu")
		(net "M_A_CPU0_CLK_DP<1>")
	)
	(segment
		(start 334.871822 -249.836686)
		(end 334.864456 -249.832368)
		(width 0.088646)
		(layer "F.Cu")
		(net "M_A_CPU0_CLK_DP<1>")
	)
	(segment
		(start 333.715106 -251.351542)
		(end 332.015592 -251.351542)
		(width 0.088646)
		(layer "F.Cu")
		(net "M_A_CPU0_CLK_DP<1>")
	)
	(segment
		(start 331.918818 -251.420376)
		(end 331.598778 -251.420376)
		(width 0.20066)
		(layer "F.Cu")
		(net "M_A_CPU0_CLK_DP<1>")
	)
	(arc
		(start 334.862932 -249.831606)
		(mid 334.675734 -249.781463)
		(end 334.488536 -249.831606)
		(width 0.088646)
		(layer "F.Cu")
		(net "M_A_CPU0_CLK_DP<1>")
	)
	(arc
		(start 335.045558 -250.097036)
		(mid 334.987215 -249.947813)
		(end 334.871822 -249.836686)
		(width 0.088646)
		(layer "F.Cu")
		(net "M_A_CPU0_CLK_DP<1>")
	)
	(arc
		(start 334.479646 -249.836686)
		(mid 334.348732 -249.973046)
		(end 334.301084 -250.155964)
		(width 0.088646)
		(layer "F.Cu")
		(net "M_A_CPU0_CLK_DP<1>")
	)
	(segment
		(start 331.25664 -250.38939)
		(end 329.78344 -251.86259)
		(width 0.20066)
		(layer "F.Cu")
		(net "M_A_CPU0_CLK_DP<0>")
	)
	(segment
		(start 306.237894 -259.968238)
		(end 305.989482 -260.21665)
		(width 0.20066)
		(layer "F.Cu")
		(net "M_A_CPU0_CLK_DP<0>")
	)
	(segment
		(start 329.78344 -251.86259)
		(end 329.35418 -252.504956)
		(width 0.20066)
		(layer "F.Cu")
		(net "M_A_CPU0_CLK_DP<0>")
	)
	(segment
		(start 307.49367 -258.081272)
		(end 307.44414 -258.20116)
		(width 0.20066)
		(layer "F.Cu")
		(net "M_A_CPU0_CLK_DP<0>")
	)
	(segment
		(start 307.956966 -257.61823)
		(end 307.49367 -258.081272)
		(width 0.20066)
		(layer "F.Cu")
		(net "M_A_CPU0_CLK_DP<0>")
	)
	(segment
		(start 333.523082 -249.867674)
		(end 333.453486 -249.902472)
		(width 0.088646)
		(layer "F.Cu")
		(net "M_A_CPU0_CLK_DP<0>")
	)
	(segment
		(start 307.322982 -259.278628)
		(end 306.633372 -259.968238)
		(width 0.20066)
		(layer "F.Cu")
		(net "M_A_CPU0_CLK_DP<0>")
	)
	(segment
		(start 333.735934 -248.528078)
		(end 333.58074 -248.797064)
		(width 0.088646)
		(layer "F.Cu")
		(net "M_A_CPU0_CLK_DP<0>")
	)
	(segment
		(start 327.23328 -254.625856)
		(end 320.787522 -254.625856)
		(width 0.20066)
		(layer "F.Cu")
		(net "M_A_CPU0_CLK_DP<0>")
	)
	(segment
		(start 333.58074 -248.797064)
		(end 333.605886 -248.890028)
		(width 0.088646)
		(layer "F.Cu")
		(net "M_A_CPU0_CLK_DP<0>")
	)
	(segment
		(start 331.918818 -250.38939)
		(end 331.25664 -250.38939)
		(width 0.20066)
		(layer "F.Cu")
		(net "M_A_CPU0_CLK_DP<0>")
	)
	(segment
		(start 329.35418 -252.504956)
		(end 327.23328 -254.625856)
		(width 0.20066)
		(layer "F.Cu")
		(net "M_A_CPU0_CLK_DP<0>")
	)
	(segment
		(start 306.633372 -259.968238)
		(end 306.237894 -259.968238)
		(width 0.20066)
		(layer "F.Cu")
		(net "M_A_CPU0_CLK_DP<0>")
	)
	(segment
		(start 320.787522 -254.625856)
		(end 307.956966 -257.61823)
		(width 0.20066)
		(layer "F.Cu")
		(net "M_A_CPU0_CLK_DP<0>")
	)
	(segment
		(start 333.13497 -249.977656)
		(end 332.88986 -249.977656)
		(width 0.088646)
		(layer "F.Cu")
		(net "M_A_CPU0_CLK_DP<0>")
	)
	(segment
		(start 307.44414 -258.20116)
		(end 307.322982 -258.493514)
		(width 0.20066)
		(layer "F.Cu")
		(net "M_A_CPU0_CLK_DP<0>")
	)
	(segment
		(start 333.831184 -249.342148)
		(end 333.83093 -249.342148)
		(width 0.088646)
		(layer "F.Cu")
		(net "M_A_CPU0_CLK_DP<0>")
	)
	(segment
		(start 333.831184 -249.327924)
		(end 333.831184 -249.342148)
		(width 0.088646)
		(layer "F.Cu")
		(net "M_A_CPU0_CLK_DP<0>")
	)
	(segment
		(start 307.322982 -258.493514)
		(end 307.322982 -259.278628)
		(width 0.20066)
		(layer "F.Cu")
		(net "M_A_CPU0_CLK_DP<0>")
	)
	(segment
		(start 331.946758 -250.38939)
		(end 331.918818 -250.38939)
		(width 0.088646)
		(layer "F.Cu")
		(net "M_A_CPU0_CLK_DP<0>")
	)
	(segment
		(start 305.989482 -260.21665)
		(end 305.443382 -260.21665)
		(width 0.20066)
		(layer "F.Cu")
		(net "M_A_CPU0_CLK_DP<0>")
	)
	(segment
		(start 332.480158 -250.320556)
		(end 332.015592 -250.320556)
		(width 0.088646)
		(layer "F.Cu")
		(net "M_A_CPU0_CLK_DP<0>")
	)
	(segment
		(start 332.015592 -250.320556)
		(end 331.946758 -250.38939)
		(width 0.088646)
		(layer "F.Cu")
		(net "M_A_CPU0_CLK_DP<0>")
	)
	(segment
		(start 332.775814 -250.0249)
		(end 332.480158 -250.320556)
		(width 0.088646)
		(layer "F.Cu")
		(net "M_A_CPU0_CLK_DP<0>")
	)
	(arc
		(start 332.88986 -249.977656)
		(mid 332.828137 -249.989933)
		(end 332.775814 -250.0249)
		(width 0.088646)
		(layer "F.Cu")
		(net "M_A_CPU0_CLK_DP<0>")
	)
	(arc
		(start 333.62265 -248.903236)
		(mid 333.773419 -249.092736)
		(end 333.831184 -249.327924)
		(width 0.088646)
		(layer "F.Cu")
		(net "M_A_CPU0_CLK_DP<0>")
	)
	(arc
		(start 333.83093 -249.342148)
		(mid 333.748377 -249.646734)
		(end 333.523082 -249.867674)
		(width 0.088646)
		(layer "F.Cu")
		(net "M_A_CPU0_CLK_DP<0>")
	)
	(arc
		(start 333.453486 -249.902472)
		(mid 333.298605 -249.958611)
		(end 333.13497 -249.977656)
		(width 0.088646)
		(layer "F.Cu")
		(net "M_A_CPU0_CLK_DP<0>")
	)
	(arc
		(start 333.605886 -248.890028)
		(mid 333.61433 -248.896553)
		(end 333.62265 -248.903236)
		(width 0.088646)
		(layer "F.Cu")
		(net "M_A_CPU0_CLK_DP<0>")
	)
	(segment
		(start 334.958944 -249.667014)
		(end 334.964278 -249.670062)
		(width 0.088646)
		(layer "F.Cu")
		(net "M_A_CPU0_CLK_DN<1>")
	)
	(segment
		(start 312.987182 -259.366766)
		(end 313.497214 -259.366766)
		(width 0.20066)
		(layer "F.Cu")
		(net "M_A_CPU0_CLK_DN<1>")
	)
	(segment
		(start 334.110838 -250.587256)
		(end 334.110838 -250.155964)
		(width 0.088646)
		(layer "F.Cu")
		(net "M_A_CPU0_CLK_DN<1>")
	)
	(segment
		(start 332.015338 -251.161296)
		(end 333.636112 -251.161296)
		(width 0.088646)
		(layer "F.Cu")
		(net "M_A_CPU0_CLK_DN<1>")
	)
	(segment
		(start 335.23682 -250.088146)
		(end 335.304638 -250.155964)
		(width 0.088646)
		(layer "F.Cu")
		(net "M_A_CPU0_CLK_DN<1>")
	)
	(segment
		(start 330.098146 -252.798834)
		(end 330.785978 -251.769626)
		(width 0.20066)
		(layer "F.Cu")
		(net "M_A_CPU0_CLK_DN<1>")
	)
	(segment
		(start 331.946758 -251.092716)
		(end 332.015338 -251.161296)
		(width 0.088646)
		(layer "F.Cu")
		(net "M_A_CPU0_CLK_DN<1>")
	)
	(segment
		(start 333.636112 -251.161296)
		(end 334.040226 -250.756928)
		(width 0.088646)
		(layer "F.Cu")
		(net "M_A_CPU0_CLK_DN<1>")
	)
	(segment
		(start 327.630028 -255.267206)
		(end 330.098146 -252.798834)
		(width 0.20066)
		(layer "F.Cu")
		(net "M_A_CPU0_CLK_DN<1>")
	)
	(segment
		(start 331.462888 -251.092716)
		(end 331.918818 -251.092716)
		(width 0.20066)
		(layer "F.Cu")
		(net "M_A_CPU0_CLK_DN<1>")
	)
	(segment
		(start 334.947768 -249.66041)
		(end 334.958182 -249.666506)
		(width 0.088646)
		(layer "F.Cu")
		(net "M_A_CPU0_CLK_DN<1>")
	)
	(segment
		(start 331.918818 -251.092716)
		(end 331.946758 -251.092716)
		(width 0.088646)
		(layer "F.Cu")
		(net "M_A_CPU0_CLK_DN<1>")
	)
	(segment
		(start 313.497214 -259.366766)
		(end 313.7916 -259.661152)
		(width 0.20066)
		(layer "F.Cu")
		(net "M_A_CPU0_CLK_DN<1>")
	)
	(segment
		(start 314.025026 -259.661152)
		(end 316.567312 -257.118866)
		(width 0.20066)
		(layer "F.Cu")
		(net "M_A_CPU0_CLK_DN<1>")
	)
	(segment
		(start 335.304638 -250.155964)
		(end 335.615534 -250.155964)
		(width 0.088646)
		(layer "F.Cu")
		(net "M_A_CPU0_CLK_DN<1>")
	)
	(segment
		(start 321.03695 -255.267206)
		(end 327.630028 -255.267206)
		(width 0.20066)
		(layer "F.Cu")
		(net "M_A_CPU0_CLK_DN<1>")
	)
	(segment
		(start 330.785978 -251.769626)
		(end 331.462888 -251.092716)
		(width 0.20066)
		(layer "F.Cu")
		(net "M_A_CPU0_CLK_DN<1>")
	)
	(segment
		(start 316.567312 -257.118866)
		(end 321.03695 -255.267206)
		(width 0.20066)
		(layer "F.Cu")
		(net "M_A_CPU0_CLK_DN<1>")
	)
	(segment
		(start 334.958182 -249.666506)
		(end 334.958944 -249.667014)
		(width 0.088646)
		(layer "F.Cu")
		(net "M_A_CPU0_CLK_DN<1>")
	)
	(segment
		(start 313.7916 -259.661152)
		(end 314.025026 -259.661152)
		(width 0.20066)
		(layer "F.Cu")
		(net "M_A_CPU0_CLK_DN<1>")
	)
	(segment
		(start 334.040226 -250.756928)
		(end 334.110838 -250.587256)
		(width 0.088646)
		(layer "F.Cu")
		(net "M_A_CPU0_CLK_DN<1>")
	)
	(arc
		(start 334.964278 -249.670062)
		(mid 335.143275 -249.838531)
		(end 335.233772 -250.067064)
		(width 0.088646)
		(layer "F.Cu")
		(net "M_A_CPU0_CLK_DN<1>")
	)
	(arc
		(start 334.110838 -250.155964)
		(mid 334.182646 -249.880268)
		(end 334.379824 -249.674634)
		(width 0.088646)
		(layer "F.Cu")
		(net "M_A_CPU0_CLK_DN<1>")
	)
	(arc
		(start 334.393286 -249.666506)
		(mid 334.669734 -249.590765)
		(end 334.947768 -249.66041)
		(width 0.088646)
		(layer "F.Cu")
		(net "M_A_CPU0_CLK_DN<1>")
	)
	(arc
		(start 334.379824 -249.674634)
		(mid 334.386526 -249.670522)
		(end 334.393286 -249.666506)
		(width 0.088646)
		(layer "F.Cu")
		(net "M_A_CPU0_CLK_DN<1>")
	)
	(arc
		(start 335.233772 -250.067064)
		(mid 335.235396 -250.077591)
		(end 335.23682 -250.088146)
		(width 0.088646)
		(layer "F.Cu")
		(net "M_A_CPU0_CLK_DN<1>")
	)
	(segment
		(start 332.641194 -249.89028)
		(end 332.401164 -250.13031)
		(width 0.088646)
		(layer "F.Cu")
		(net "M_A_CPU0_CLK_DN<0>")
	)
	(segment
		(start 312.486294 -256.097278)
		(end 311.899808 -256.23393)
		(width 0.20066)
		(layer "F.Cu")
		(net "M_A_CPU0_CLK_DN<0>")
	)
	(segment
		(start 308.976522 -257.043936)
		(end 307.791358 -257.320288)
		(width 0.20066)
		(layer "F.Cu")
		(net "M_A_CPU0_CLK_DN<0>")
	)
	(segment
		(start 314.05068 -255.860296)
		(end 313.901328 -255.767332)
		(width 0.20066)
		(layer "F.Cu")
		(net "M_A_CPU0_CLK_DN<0>")
	)
	(segment
		(start 314.636912 -255.723644)
		(end 314.05068 -255.860296)
		(width 0.20066)
		(layer "F.Cu")
		(net "M_A_CPU0_CLK_DN<0>")
	)
	(segment
		(start 333.43342 -249.699526)
		(end 333.368396 -249.732292)
		(width 0.088646)
		(layer "F.Cu")
		(net "M_A_CPU0_CLK_DN<0>")
	)
	(segment
		(start 307.791358 -257.320288)
		(end 307.21554 -257.895598)
		(width 0.20066)
		(layer "F.Cu")
		(net "M_A_CPU0_CLK_DN<0>")
	)
	(segment
		(start 331.918818 -250.06173)
		(end 331.12075 -250.06173)
		(width 0.20066)
		(layer "F.Cu")
		(net "M_A_CPU0_CLK_DN<0>")
	)
	(segment
		(start 329.099418 -252.295914)
		(end 327.09739 -254.298196)
		(width 0.20066)
		(layer "F.Cu")
		(net "M_A_CPU0_CLK_DN<0>")
	)
	(segment
		(start 309.655972 -256.757424)
		(end 309.069486 -256.89433)
		(width 0.20066)
		(layer "F.Cu")
		(net "M_A_CPU0_CLK_DN<0>")
	)
	(segment
		(start 306.995322 -258.428236)
		(end 306.995322 -259.142738)
		(width 0.20066)
		(layer "F.Cu")
		(net "M_A_CPU0_CLK_DN<0>")
	)
	(segment
		(start 333.420974 -249.073162)
		(end 333.502 -249.051572)
		(width 0.088646)
		(layer "F.Cu")
		(net "M_A_CPU0_CLK_DN<0>")
	)
	(segment
		(start 312.635646 -256.190242)
		(end 312.486294 -256.097278)
		(width 0.20066)
		(layer "F.Cu")
		(net "M_A_CPU0_CLK_DN<0>")
	)
	(segment
		(start 332.015338 -250.13031)
		(end 331.946758 -250.06173)
		(width 0.088646)
		(layer "F.Cu")
		(net "M_A_CPU0_CLK_DN<0>")
	)
	(segment
		(start 327.09739 -254.298196)
		(end 320.749676 -254.298196)
		(width 0.20066)
		(layer "F.Cu")
		(net "M_A_CPU0_CLK_DN<0>")
	)
	(segment
		(start 333.26578 -249.342148)
		(end 333.420974 -249.073162)
		(width 0.088646)
		(layer "F.Cu")
		(net "M_A_CPU0_CLK_DN<0>")
	)
	(segment
		(start 307.21554 -257.895598)
		(end 307.089302 -258.20116)
		(width 0.20066)
		(layer "F.Cu")
		(net "M_A_CPU0_CLK_DN<0>")
	)
	(segment
		(start 306.497482 -259.640578)
		(end 306.255166 -259.640578)
		(width 0.20066)
		(layer "F.Cu")
		(net "M_A_CPU0_CLK_DN<0>")
	)
	(segment
		(start 313.221878 -256.05359)
		(end 312.635646 -256.190242)
		(width 0.20066)
		(layer "F.Cu")
		(net "M_A_CPU0_CLK_DN<0>")
	)
	(segment
		(start 311.220612 -256.520188)
		(end 311.07126 -256.427478)
		(width 0.20066)
		(layer "F.Cu")
		(net "M_A_CPU0_CLK_DN<0>")
	)
	(segment
		(start 310.39181 -256.713736)
		(end 309.805578 -256.850388)
		(width 0.20066)
		(layer "F.Cu")
		(net "M_A_CPU0_CLK_DN<0>")
	)
	(segment
		(start 315.465714 -255.53035)
		(end 315.316362 -255.437386)
		(width 0.20066)
		(layer "F.Cu")
		(net "M_A_CPU0_CLK_DN<0>")
	)
	(segment
		(start 311.806844 -256.383536)
		(end 311.220612 -256.520188)
		(width 0.20066)
		(layer "F.Cu")
		(net "M_A_CPU0_CLK_DN<0>")
	)
	(segment
		(start 311.899808 -256.23393)
		(end 311.806844 -256.383536)
		(width 0.20066)
		(layer "F.Cu")
		(net "M_A_CPU0_CLK_DN<0>")
	)
	(segment
		(start 332.401164 -250.13031)
		(end 332.015338 -250.13031)
		(width 0.088646)
		(layer "F.Cu")
		(net "M_A_CPU0_CLK_DN<0>")
	)
	(segment
		(start 307.089302 -258.20116)
		(end 306.995322 -258.428236)
		(width 0.20066)
		(layer "F.Cu")
		(net "M_A_CPU0_CLK_DN<0>")
	)
	(segment
		(start 306.995322 -259.142738)
		(end 306.497482 -259.640578)
		(width 0.20066)
		(layer "F.Cu")
		(net "M_A_CPU0_CLK_DN<0>")
	)
	(segment
		(start 331.12075 -250.06173)
		(end 329.528678 -251.653548)
		(width 0.20066)
		(layer "F.Cu")
		(net "M_A_CPU0_CLK_DN<0>")
	)
	(segment
		(start 315.316362 -255.437386)
		(end 314.729876 -255.574038)
		(width 0.20066)
		(layer "F.Cu")
		(net "M_A_CPU0_CLK_DN<0>")
	)
	(segment
		(start 306.255166 -259.640578)
		(end 305.981354 -259.366766)
		(width 0.20066)
		(layer "F.Cu")
		(net "M_A_CPU0_CLK_DN<0>")
	)
	(segment
		(start 314.729876 -255.574038)
		(end 314.636912 -255.723644)
		(width 0.20066)
		(layer "F.Cu")
		(net "M_A_CPU0_CLK_DN<0>")
	)
	(segment
		(start 309.805578 -256.850388)
		(end 309.655972 -256.757424)
		(width 0.20066)
		(layer "F.Cu")
		(net "M_A_CPU0_CLK_DN<0>")
	)
	(segment
		(start 310.48452 -256.56413)
		(end 310.39181 -256.713736)
		(width 0.20066)
		(layer "F.Cu")
		(net "M_A_CPU0_CLK_DN<0>")
	)
	(segment
		(start 311.07126 -256.427478)
		(end 310.48452 -256.56413)
		(width 0.20066)
		(layer "F.Cu")
		(net "M_A_CPU0_CLK_DN<0>")
	)
	(segment
		(start 329.528678 -251.653548)
		(end 329.099418 -252.295914)
		(width 0.20066)
		(layer "F.Cu")
		(net "M_A_CPU0_CLK_DN<0>")
	)
	(segment
		(start 305.981354 -259.366766)
		(end 305.443382 -259.366766)
		(width 0.20066)
		(layer "F.Cu")
		(net "M_A_CPU0_CLK_DN<0>")
	)
	(segment
		(start 333.64043 -249.342148)
		(end 333.640684 -249.342402)
		(width 0.088646)
		(layer "F.Cu")
		(net "M_A_CPU0_CLK_DN<0>")
	)
	(segment
		(start 333.135224 -249.78741)
		(end 332.889606 -249.78741)
		(width 0.088646)
		(layer "F.Cu")
		(net "M_A_CPU0_CLK_DN<0>")
	)
	(segment
		(start 320.749676 -254.298196)
		(end 315.465714 -255.53035)
		(width 0.20066)
		(layer "F.Cu")
		(net "M_A_CPU0_CLK_DN<0>")
	)
	(segment
		(start 313.314842 -255.903984)
		(end 313.221878 -256.05359)
		(width 0.20066)
		(layer "F.Cu")
		(net "M_A_CPU0_CLK_DN<0>")
	)
	(segment
		(start 309.069486 -256.89433)
		(end 308.976522 -257.043936)
		(width 0.20066)
		(layer "F.Cu")
		(net "M_A_CPU0_CLK_DN<0>")
	)
	(segment
		(start 313.901328 -255.767332)
		(end 313.314842 -255.903984)
		(width 0.20066)
		(layer "F.Cu")
		(net "M_A_CPU0_CLK_DN<0>")
	)
	(segment
		(start 331.946758 -250.06173)
		(end 331.918818 -250.06173)
		(width 0.088646)
		(layer "F.Cu")
		(net "M_A_CPU0_CLK_DN<0>")
	)
	(arc
		(start 333.640684 -249.342402)
		(mid 333.585055 -249.548823)
		(end 333.43342 -249.699526)
		(width 0.088646)
		(layer "F.Cu")
		(net "M_A_CPU0_CLK_DN<0>")
	)
	(arc
		(start 333.502 -249.051572)
		(mid 333.604021 -249.181234)
		(end 333.64043 -249.342148)
		(width 0.088646)
		(layer "F.Cu")
		(net "M_A_CPU0_CLK_DN<0>")
	)
	(arc
		(start 332.889606 -249.78741)
		(mid 332.755201 -249.814203)
		(end 332.641194 -249.89028)
		(width 0.088646)
		(layer "F.Cu")
		(net "M_A_CPU0_CLK_DN<0>")
	)
	(arc
		(start 333.368396 -249.732292)
		(mid 333.255015 -249.773404)
		(end 333.135224 -249.78741)
		(width 0.088646)
		(layer "F.Cu")
		(net "M_A_CPU0_CLK_DN<0>")
	)
	(segment
		(start 349.352362 -255.547368)
		(end 349.352616 -255.547622)
		(width 0.20066)
		(layer "F.Cu")
		(net "M_A_CPU0_ALERT_N")
	)
	(segment
		(start 304.626772 -269.141702)
		(end 304.161698 -269.141702)
		(width 0.101854)
		(layer "F.Cu")
		(net "M_A_CPU0_ALERT_N")
	)
	(segment
		(start 308.887114 -269.566644)
		(end 307.20665 -269.566644)
		(width 0.20066)
		(layer "F.Cu")
		(net "M_A_CPU0_ALERT_N")
	)
	(segment
		(start 306.781708 -269.141702)
		(end 306.644294 -269.141702)
		(width 0.20066)
		(layer "F.Cu")
		(net "M_A_CPU0_ALERT_N")
	)
	(segment
		(start 349.352362 -255.011682)
		(end 349.352362 -255.547368)
		(width 0.20066)
		(layer "F.Cu")
		(net "M_A_CPU0_ALERT_N")
	)
	(segment
		(start 303.700434 -269.141702)
		(end 303.523396 -269.31874)
		(width 0.20066)
		(layer "F.Cu")
		(net "M_A_CPU0_ALERT_N")
	)
	(segment
		(start 306.644294 -269.141702)
		(end 306.64404 -269.141702)
		(width 0.101854)
		(layer "F.Cu")
		(net "M_A_CPU0_ALERT_N")
	)
	(segment
		(start 306.64404 -269.141702)
		(end 304.626772 -269.141702)
		(width 0.1016)
		(layer "F.Cu")
		(net "M_A_CPU0_ALERT_N")
	)
	(segment
		(start 303.523396 -269.58417)
		(end 303.289208 -269.818358)
		(width 0.20066)
		(layer "F.Cu")
		(net "M_A_CPU0_ALERT_N")
	)
	(segment
		(start 304.161698 -269.141702)
		(end 303.700434 -269.141702)
		(width 0.20066)
		(layer "F.Cu")
		(net "M_A_CPU0_ALERT_N")
	)
	(segment
		(start 303.289208 -269.818358)
		(end 302.199548 -269.818358)
		(width 0.20066)
		(layer "F.Cu")
		(net "M_A_CPU0_ALERT_N")
	)
	(segment
		(start 307.20665 -269.566644)
		(end 306.781708 -269.141702)
		(width 0.20066)
		(layer "F.Cu")
		(net "M_A_CPU0_ALERT_N")
	)
	(segment
		(start 301.947834 -269.566644)
		(end 301.343314 -269.566644)
		(width 0.20066)
		(layer "F.Cu")
		(net "M_A_CPU0_ALERT_N")
	)
	(segment
		(start 302.199548 -269.818358)
		(end 301.947834 -269.566644)
		(width 0.20066)
		(layer "F.Cu")
		(net "M_A_CPU0_ALERT_N")
	)
	(segment
		(start 309.992014 -269.566644)
		(end 308.887114 -269.566644)
		(width 0.20066)
		(layer "F.Cu")
		(net "M_A_CPU0_ALERT_N")
	)
	(segment
		(start 303.523396 -269.31874)
		(end 303.523396 -269.58417)
		(width 0.20066)
		(layer "F.Cu")
		(net "M_A_CPU0_ALERT_N")
	)
	(via
		(at 349.352616 -255.547622)
		(size 0.4572)
		(drill 0.2032)
		(layers "F.Cu" "B.Cu")
		(net "M_A_CPU0_ALERT_N")
	)
	(via
		(at 309.992014 -269.566644)
		(size 0.4572)
		(drill 0.2032)
		(layers "F.Cu" "B.Cu")
		(net "M_A_CPU0_ALERT_N")
	)
	(segment
		(start 338.309712 -260.023864)
		(end 338.29625 -260.01599)
		(width 0.18288)
		(layer "In4.Cu")
		(net "M_A_CPU0_ALERT_N")
	)
	(segment
		(start 342.068912 -260.023864)
		(end 342.05545 -260.01599)
		(width 0.18288)
		(layer "In4.Cu")
		(net "M_A_CPU0_ALERT_N")
	)
	(segment
		(start 335.965038 -259.212842)
		(end 335.960212 -259.210048)
		(width 0.18288)
		(layer "In4.Cu")
		(net "M_A_CPU0_ALERT_N")
	)
	(segment
		(start 345.828112 -258.395978)
		(end 345.81846 -258.39039)
		(width 0.18288)
		(layer "In4.Cu")
		(net "M_A_CPU0_ALERT_N")
	)
	(segment
		(start 346.768166 -258.395978)
		(end 346.758514 -258.39039)
		(width 0.18288)
		(layer "In4.Cu")
		(net "M_A_CPU0_ALERT_N")
	)
	(segment
		(start 341.129112 -260.023864)
		(end 341.11565 -260.01599)
		(width 0.18288)
		(layer "In4.Cu")
		(net "M_A_CPU0_ALERT_N")
	)
	(segment
		(start 310.67375 -269.566644)
		(end 309.992014 -269.566644)
		(width 0.18288)
		(layer "In4.Cu")
		(net "M_A_CPU0_ALERT_N")
	)
	(segment
		(start 332.2574 -259.5245)
		(end 326.736202 -259.5245)
		(width 0.18288)
		(layer "In4.Cu")
		(net "M_A_CPU0_ALERT_N")
	)
	(segment
		(start 332.62189 -259.25653)
		(end 332.422246 -259.456174)
		(width 0.18288)
		(layer "In4.Cu")
		(net "M_A_CPU0_ALERT_N")
	)
	(segment
		(start 312.533538 -268.57198)
		(end 311.668414 -268.57198)
		(width 0.18288)
		(layer "In4.Cu")
		(net "M_A_CPU0_ALERT_N")
	)
	(segment
		(start 343.243916 -258.802632)
		(end 343.243916 -258.80314)
		(width 0.18288)
		(layer "In4.Cu")
		(net "M_A_CPU0_ALERT_N")
	)
	(segment
		(start 343.022936 -259.201666)
		(end 343.008712 -259.210048)
		(width 0.18288)
		(layer "In4.Cu")
		(net "M_A_CPU0_ALERT_N")
	)
	(segment
		(start 347.473016 -257.974592)
		(end 347.473016 -257.98907)
		(width 0.18288)
		(layer "In4.Cu")
		(net "M_A_CPU0_ALERT_N")
	)
	(segment
		(start 326.303894 -259.70357)
		(end 317.935864 -263.169654)
		(width 0.18288)
		(layer "In4.Cu")
		(net "M_A_CPU0_ALERT_N")
	)
	(segment
		(start 348.191836 -256.759964)
		(end 348.177612 -256.768346)
		(width 0.18288)
		(layer "In4.Cu")
		(net "M_A_CPU0_ALERT_N")
	)
	(segment
		(start 343.948512 -258.395978)
		(end 343.93505 -258.388104)
		(width 0.18288)
		(layer "In4.Cu")
		(net "M_A_CPU0_ALERT_N")
	)
	(segment
		(start 342.543638 -260.02107)
		(end 342.538812 -260.023864)
		(width 0.18288)
		(layer "In4.Cu")
		(net "M_A_CPU0_ALERT_N")
	)
	(segment
		(start 347.721936 -257.57378)
		(end 347.707712 -257.582162)
		(width 0.18288)
		(layer "In4.Cu")
		(net "M_A_CPU0_ALERT_N")
	)
	(segment
		(start 317.935864 -263.169654)
		(end 312.533538 -268.57198)
		(width 0.18288)
		(layer "In4.Cu")
		(net "M_A_CPU0_ALERT_N")
	)
	(segment
		(start 336.430366 -260.023864)
		(end 336.430112 -260.023864)
		(width 0.18288)
		(layer "In4.Cu")
		(net "M_A_CPU0_ALERT_N")
	)
	(segment
		(start 337.369912 -260.023864)
		(end 337.35645 -260.01599)
		(width 0.18288)
		(layer "In4.Cu")
		(net "M_A_CPU0_ALERT_N")
	)
	(segment
		(start 343.008712 -259.210048)
		(end 343.003886 -259.212842)
		(width 0.18288)
		(layer "In4.Cu")
		(net "M_A_CPU0_ALERT_N")
	)
	(segment
		(start 347.942916 -257.165602)
		(end 347.942916 -257.175254)
		(width 0.18288)
		(layer "In4.Cu")
		(net "M_A_CPU0_ALERT_N")
	)
	(segment
		(start 348.647766 -255.95453)
		(end 348.64294 -255.957324)
		(width 0.18288)
		(layer "In4.Cu")
		(net "M_A_CPU0_ALERT_N")
	)
	(segment
		(start 344.888566 -258.395978)
		(end 344.878914 -258.39039)
		(width 0.18288)
		(layer "In4.Cu")
		(net "M_A_CPU0_ALERT_N")
	)
	(segment
		(start 339.249766 -260.023864)
		(end 339.240114 -260.018276)
		(width 0.18288)
		(layer "In4.Cu")
		(net "M_A_CPU0_ALERT_N")
	)
	(segment
		(start 349.352616 -255.547622)
		(end 348.647766 -255.95453)
		(width 0.18288)
		(layer "In4.Cu")
		(net "M_A_CPU0_ALERT_N")
	)
	(segment
		(start 326.736202 -259.5245)
		(end 326.303894 -259.70357)
		(width 0.18288)
		(layer "In4.Cu")
		(net "M_A_CPU0_ALERT_N")
	)
	(segment
		(start 336.430112 -260.023864)
		(end 336.425286 -260.02107)
		(width 0.18288)
		(layer "In4.Cu")
		(net "M_A_CPU0_ALERT_N")
	)
	(segment
		(start 311.668414 -268.57198)
		(end 310.67375 -269.566644)
		(width 0.18288)
		(layer "In4.Cu")
		(net "M_A_CPU0_ALERT_N")
	)
	(segment
		(start 346.768166 -258.396232)
		(end 346.768166 -258.395978)
		(width 0.18288)
		(layer "In4.Cu")
		(net "M_A_CPU0_ALERT_N")
	)
	(segment
		(start 347.242892 -258.393184)
		(end 347.238066 -258.395978)
		(width 0.18288)
		(layer "In4.Cu")
		(net "M_A_CPU0_ALERT_N")
	)
	(segment
		(start 339.719412 -260.023864)
		(end 339.70976 -260.029452)
		(width 0.18288)
		(layer "In4.Cu")
		(net "M_A_CPU0_ALERT_N")
	)
	(segment
		(start 347.238066 -258.395978)
		(end 347.237558 -258.396232)
		(width 0.18288)
		(layer "In4.Cu")
		(net "M_A_CPU0_ALERT_N")
	)
	(arc
		(start 340.659212 -260.023864)
		(mid 340.424262 -260.086824)
		(end 340.189312 -260.023864)
		(width 0.18288)
		(layer "In4.Cu")
		(net "M_A_CPU0_ALERT_N")
	)
	(arc
		(start 348.412816 -256.361438)
		(mid 348.353878 -256.58929)
		(end 348.191836 -256.759964)
		(width 0.18288)
		(layer "In4.Cu")
		(net "M_A_CPU0_ALERT_N")
	)
	(arc
		(start 344.418412 -258.395978)
		(mid 344.183462 -258.458938)
		(end 343.948512 -258.395978)
		(width 0.18288)
		(layer "In4.Cu")
		(net "M_A_CPU0_ALERT_N")
	)
	(arc
		(start 336.195162 -259.616956)
		(mid 336.133599 -259.384433)
		(end 335.965038 -259.212842)
		(width 0.18288)
		(layer "In4.Cu")
		(net "M_A_CPU0_ALERT_N")
	)
	(arc
		(start 341.11565 -260.01599)
		(mid 340.886397 -259.960746)
		(end 340.659212 -260.023864)
		(width 0.18288)
		(layer "In4.Cu")
		(net "M_A_CPU0_ALERT_N")
	)
	(arc
		(start 344.878914 -258.39039)
		(mid 344.647929 -258.332939)
		(end 344.418412 -258.395978)
		(width 0.18288)
		(layer "In4.Cu")
		(net "M_A_CPU0_ALERT_N")
	)
	(arc
		(start 347.942916 -257.175254)
		(mid 347.883978 -257.403106)
		(end 347.721936 -257.57378)
		(width 0.18288)
		(layer "In4.Cu")
		(net "M_A_CPU0_ALERT_N")
	)
	(arc
		(start 343.003886 -259.212842)
		(mid 342.83533 -259.384436)
		(end 342.773762 -259.616956)
		(width 0.18288)
		(layer "In4.Cu")
		(net "M_A_CPU0_ALERT_N")
	)
	(arc
		(start 338.29625 -260.01599)
		(mid 338.066997 -259.960746)
		(end 337.839812 -260.023864)
		(width 0.18288)
		(layer "In4.Cu")
		(net "M_A_CPU0_ALERT_N")
	)
	(arc
		(start 342.773762 -259.616956)
		(mid 342.712199 -259.849479)
		(end 342.543638 -260.02107)
		(width 0.18288)
		(layer "In4.Cu")
		(net "M_A_CPU0_ALERT_N")
	)
	(arc
		(start 347.707712 -257.582162)
		(mid 347.539408 -257.747902)
		(end 347.473016 -257.974592)
		(width 0.18288)
		(layer "In4.Cu")
		(net "M_A_CPU0_ALERT_N")
	)
	(arc
		(start 336.900012 -260.023864)
		(mid 336.665206 -260.086731)
		(end 336.430366 -260.023864)
		(width 0.18288)
		(layer "In4.Cu")
		(net "M_A_CPU0_ALERT_N")
	)
	(arc
		(start 339.240114 -260.018276)
		(mid 339.009129 -259.960793)
		(end 338.779612 -260.023864)
		(width 0.18288)
		(layer "In4.Cu")
		(net "M_A_CPU0_ALERT_N")
	)
	(arc
		(start 342.05545 -260.01599)
		(mid 341.826197 -259.960746)
		(end 341.599012 -260.023864)
		(width 0.18288)
		(layer "In4.Cu")
		(net "M_A_CPU0_ALERT_N")
	)
	(arc
		(start 343.243916 -258.80314)
		(mid 343.184978 -259.030992)
		(end 343.022936 -259.201666)
		(width 0.18288)
		(layer "In4.Cu")
		(net "M_A_CPU0_ALERT_N")
	)
	(arc
		(start 334.550512 -259.210048)
		(mid 334.315562 -259.273008)
		(end 334.080612 -259.210048)
		(width 0.18288)
		(layer "In4.Cu")
		(net "M_A_CPU0_ALERT_N")
	)
	(arc
		(start 343.93505 -258.388104)
		(mid 343.705797 -258.33289)
		(end 343.478612 -258.395978)
		(width 0.18288)
		(layer "In4.Cu")
		(net "M_A_CPU0_ALERT_N")
	)
	(arc
		(start 348.177612 -256.768346)
		(mid 348.008162 -256.936192)
		(end 347.942916 -257.165602)
		(width 0.18288)
		(layer "In4.Cu")
		(net "M_A_CPU0_ALERT_N")
	)
	(arc
		(start 347.473016 -257.98907)
		(mid 347.411453 -258.221593)
		(end 347.242892 -258.393184)
		(width 0.18288)
		(layer "In4.Cu")
		(net "M_A_CPU0_ALERT_N")
	)
	(arc
		(start 337.35645 -260.01599)
		(mid 337.127197 -259.960746)
		(end 336.900012 -260.023864)
		(width 0.18288)
		(layer "In4.Cu")
		(net "M_A_CPU0_ALERT_N")
	)
	(arc
		(start 340.189312 -260.023864)
		(mid 339.954362 -259.960904)
		(end 339.719412 -260.023864)
		(width 0.18288)
		(layer "In4.Cu")
		(net "M_A_CPU0_ALERT_N")
	)
	(arc
		(start 348.64294 -255.957324)
		(mid 348.474384 -256.128918)
		(end 348.412816 -256.361438)
		(width 0.18288)
		(layer "In4.Cu")
		(net "M_A_CPU0_ALERT_N")
	)
	(arc
		(start 339.70976 -260.029452)
		(mid 339.479029 -260.086813)
		(end 339.249766 -260.023864)
		(width 0.18288)
		(layer "In4.Cu")
		(net "M_A_CPU0_ALERT_N")
	)
	(arc
		(start 335.020412 -259.210048)
		(mid 334.785462 -259.147088)
		(end 334.550512 -259.210048)
		(width 0.18288)
		(layer "In4.Cu")
		(net "M_A_CPU0_ALERT_N")
	)
	(arc
		(start 346.758514 -258.39039)
		(mid 346.527529 -258.332939)
		(end 346.298012 -258.395978)
		(width 0.18288)
		(layer "In4.Cu")
		(net "M_A_CPU0_ALERT_N")
	)
	(arc
		(start 338.779612 -260.023864)
		(mid 338.544662 -260.086824)
		(end 338.309712 -260.023864)
		(width 0.18288)
		(layer "In4.Cu")
		(net "M_A_CPU0_ALERT_N")
	)
	(arc
		(start 335.960212 -259.210048)
		(mid 335.725262 -259.147088)
		(end 335.490312 -259.210048)
		(width 0.18288)
		(layer "In4.Cu")
		(net "M_A_CPU0_ALERT_N")
	)
	(arc
		(start 345.81846 -258.39039)
		(mid 345.587729 -258.33306)
		(end 345.358466 -258.395978)
		(width 0.18288)
		(layer "In4.Cu")
		(net "M_A_CPU0_ALERT_N")
	)
	(arc
		(start 341.599012 -260.023864)
		(mid 341.364062 -260.086824)
		(end 341.129112 -260.023864)
		(width 0.18288)
		(layer "In4.Cu")
		(net "M_A_CPU0_ALERT_N")
	)
	(arc
		(start 345.358466 -258.395978)
		(mid 345.123516 -258.458938)
		(end 344.888566 -258.395978)
		(width 0.18288)
		(layer "In4.Cu")
		(net "M_A_CPU0_ALERT_N")
	)
	(arc
		(start 333.610712 -259.210048)
		(mid 333.375762 -259.273008)
		(end 333.140812 -259.210048)
		(width 0.18288)
		(layer "In4.Cu")
		(net "M_A_CPU0_ALERT_N")
	)
	(arc
		(start 335.490312 -259.210048)
		(mid 335.255362 -259.273008)
		(end 335.020412 -259.210048)
		(width 0.18288)
		(layer "In4.Cu")
		(net "M_A_CPU0_ALERT_N")
	)
	(arc
		(start 347.237558 -258.396232)
		(mid 347.002862 -258.459099)
		(end 346.768166 -258.396232)
		(width 0.18288)
		(layer "In4.Cu")
		(net "M_A_CPU0_ALERT_N")
	)
	(arc
		(start 333.140812 -259.210048)
		(mid 332.964855 -259.150678)
		(end 332.779624 -259.164074)
		(width 0.18288)
		(layer "In4.Cu")
		(net "M_A_CPU0_ALERT_N")
	)
	(arc
		(start 343.478612 -258.395978)
		(mid 343.306799 -258.567871)
		(end 343.243916 -258.802632)
		(width 0.18288)
		(layer "In4.Cu")
		(net "M_A_CPU0_ALERT_N")
	)
	(arc
		(start 336.425286 -260.02107)
		(mid 336.25673 -259.849476)
		(end 336.195162 -259.616956)
		(width 0.18288)
		(layer "In4.Cu")
		(net "M_A_CPU0_ALERT_N")
	)
	(arc
		(start 332.422246 -259.456174)
		(mid 332.346628 -259.506763)
		(end 332.2574 -259.5245)
		(width 0.18288)
		(layer "In4.Cu")
		(net "M_A_CPU0_ALERT_N")
	)
	(arc
		(start 332.779624 -259.164074)
		(mid 332.694794 -259.200128)
		(end 332.62189 -259.25653)
		(width 0.18288)
		(layer "In4.Cu")
		(net "M_A_CPU0_ALERT_N")
	)
	(arc
		(start 334.080612 -259.210048)
		(mid 333.845662 -259.147088)
		(end 333.610712 -259.210048)
		(width 0.18288)
		(layer "In4.Cu")
		(net "M_A_CPU0_ALERT_N")
	)
	(arc
		(start 337.839812 -260.023864)
		(mid 337.604862 -260.086824)
		(end 337.369912 -260.023864)
		(width 0.18288)
		(layer "In4.Cu")
		(net "M_A_CPU0_ALERT_N")
	)
	(arc
		(start 342.538812 -260.023864)
		(mid 342.303862 -260.086824)
		(end 342.068912 -260.023864)
		(width 0.18288)
		(layer "In4.Cu")
		(net "M_A_CPU0_ALERT_N")
	)
	(arc
		(start 346.298012 -258.395978)
		(mid 346.063062 -258.458938)
		(end 345.828112 -258.395978)
		(width 0.18288)
		(layer "In4.Cu")
		(net "M_A_CPU0_ALERT_N")
	)
	(segment
		(start 275.09851 -94.151958)
		(end 275.09851 -93.741494)
		(width 0.12954)
		(layer "F.Cu")
		(net "MB_FRU_ADDR2")
	)
	(segment
		(start 279.781 -93.78569)
		(end 278.063706 -93.78569)
		(width 0.12954)
		(layer "F.Cu")
		(net "MB_FRU_ADDR2")
	)
	(segment
		(start 277.417276 -94.343728)
		(end 275.29028 -94.343728)
		(width 0.12954)
		(layer "F.Cu")
		(net "MB_FRU_ADDR2")
	)
	(segment
		(start 278.01951 -93.741494)
		(end 277.417276 -94.343728)
		(width 0.12954)
		(layer "F.Cu")
		(net "MB_FRU_ADDR2")
	)
	(segment
		(start 278.063706 -93.78569)
		(end 278.01951 -93.741494)
		(width 0.12954)
		(layer "F.Cu")
		(net "MB_FRU_ADDR2")
	)
	(segment
		(start 275.29028 -94.343728)
		(end 275.09851 -94.151958)
		(width 0.12954)
		(layer "F.Cu")
		(net "MB_FRU_ADDR2")
	)
	(segment
		(start 281.794966 -93.78569)
		(end 279.781 -93.78569)
		(width 0.12954)
		(layer "F.Cu")
		(net "MB_FRU_ADDR2")
	)
	(via
		(at 279.781 -93.78569)
		(size 0.762)
		(drill 0.381)
		(layers "F.Cu" "B.Cu")
		(net "MB_FRU_ADDR2")
	)
	(segment
		(start 278.061166 -95.05569)
		(end 278.03475 -95.029274)
		(width 0.12954)
		(layer "F.Cu")
		(net "MB_FRU_ADDR1")
	)
	(segment
		(start 277.429976 -95.634048)
		(end 275.24964 -95.634048)
		(width 0.12954)
		(layer "F.Cu")
		(net "MB_FRU_ADDR1")
	)
	(segment
		(start 275.11375 -95.498158)
		(end 275.11375 -95.029274)
		(width 0.12954)
		(layer "F.Cu")
		(net "MB_FRU_ADDR1")
	)
	(segment
		(start 275.24964 -95.634048)
		(end 275.11375 -95.498158)
		(width 0.12954)
		(layer "F.Cu")
		(net "MB_FRU_ADDR1")
	)
	(segment
		(start 281.794966 -95.05569)
		(end 279.781 -95.05569)
		(width 0.12954)
		(layer "F.Cu")
		(net "MB_FRU_ADDR1")
	)
	(segment
		(start 279.781 -95.05569)
		(end 278.061166 -95.05569)
		(width 0.12954)
		(layer "F.Cu")
		(net "MB_FRU_ADDR1")
	)
	(segment
		(start 278.03475 -95.029274)
		(end 277.429976 -95.634048)
		(width 0.12954)
		(layer "F.Cu")
		(net "MB_FRU_ADDR1")
	)
	(via
		(at 279.781 -95.05569)
		(size 0.762)
		(drill 0.381)
		(layers "F.Cu" "B.Cu")
		(net "MB_FRU_ADDR1")
	)
	(segment
		(start 279.781 -96.32569)
		(end 278.054054 -96.32569)
		(width 0.12954)
		(layer "F.Cu")
		(net "MB_FRU_ADDR0")
	)
	(segment
		(start 277.424896 -96.954848)
		(end 275.26488 -96.954848)
		(width 0.12954)
		(layer "F.Cu")
		(net "MB_FRU_ADDR0")
	)
	(segment
		(start 278.054054 -96.32569)
		(end 278.04999 -96.329754)
		(width 0.12954)
		(layer "F.Cu")
		(net "MB_FRU_ADDR0")
	)
	(segment
		(start 275.26488 -96.954848)
		(end 275.12899 -96.818958)
		(width 0.12954)
		(layer "F.Cu")
		(net "MB_FRU_ADDR0")
	)
	(segment
		(start 281.794966 -96.32569)
		(end 279.781 -96.32569)
		(width 0.12954)
		(layer "F.Cu")
		(net "MB_FRU_ADDR0")
	)
	(segment
		(start 275.12899 -96.818958)
		(end 275.12899 -96.329754)
		(width 0.12954)
		(layer "F.Cu")
		(net "MB_FRU_ADDR0")
	)
	(segment
		(start 278.04999 -96.329754)
		(end 277.424896 -96.954848)
		(width 0.12954)
		(layer "F.Cu")
		(net "MB_FRU_ADDR0")
	)
	(via
		(at 279.781 -96.32569)
		(size 0.762)
		(drill 0.381)
		(layers "F.Cu" "B.Cu")
		(net "MB_FRU_ADDR0")
	)
	(segment
		(start 165.605714 -43.525948)
		(end 164.92093 -43.525948)
		(width 0.12954)
		(layer "F.Cu")
		(net "M2_SSD0_CLKREQ_EN_N_BUF")
	)
	(segment
		(start 164.92093 -42.255948)
		(end 164.92093 -43.525948)
		(width 0.12954)
		(layer "F.Cu")
		(net "M2_SSD0_CLKREQ_EN_N_BUF")
	)
	(segment
		(start 166.72941 -43.549824)
		(end 166.155624 -42.976038)
		(width 0.12954)
		(layer "F.Cu")
		(net "M2_SSD0_CLKREQ_EN_N_BUF")
	)
	(segment
		(start 166.155624 -42.976038)
		(end 165.605714 -43.525948)
		(width 0.12954)
		(layer "F.Cu")
		(net "M2_SSD0_CLKREQ_EN_N_BUF")
	)
	(segment
		(start 169.557954 -43.549824)
		(end 166.72941 -43.549824)
		(width 0.12954)
		(layer "F.Cu")
		(net "M2_SSD0_CLKREQ_EN_N_BUF")
	)
	(via
		(at 166.155624 -42.976038)
		(size 0.762)
		(drill 0.381)
		(layers "F.Cu" "B.Cu")
		(net "M2_SSD0_CLKREQ_EN_N_BUF")
	)
	(segment
		(start 332.528418 -33.557464)
		(end 332.528418 -31.231332)
		(width 0.0889)
		(layer "F.Cu")
		(net "M2_SSD0_CLKREQ_EN_N")
	)
	(segment
		(start 332.47584 -29.229812)
		(end 331.936344 -27.927808)
		(width 0.12954)
		(layer "F.Cu")
		(net "M2_SSD0_CLKREQ_EN_N")
	)
	(segment
		(start 333.89824 -37.63518)
		(end 333.89824 -34.927286)
		(width 0.0889)
		(layer "F.Cu")
		(net "M2_SSD0_CLKREQ_EN_N")
	)
	(segment
		(start 132.1816 -42.784522)
		(end 132.475732 -42.49039)
		(width 0.12954)
		(layer "F.Cu")
		(net "M2_SSD0_CLKREQ_EN_N")
	)
	(segment
		(start 332.87335 -29.627322)
		(end 332.47584 -29.229812)
		(width 0.12954)
		(layer "F.Cu")
		(net "M2_SSD0_CLKREQ_EN_N")
	)
	(segment
		(start 132.669026 -43.271948)
		(end 132.1816 -42.784522)
		(width 0.12954)
		(layer "F.Cu")
		(net "M2_SSD0_CLKREQ_EN_N")
	)
	(segment
		(start 333.89824 -34.927286)
		(end 332.528418 -33.557464)
		(width 0.0889)
		(layer "F.Cu")
		(net "M2_SSD0_CLKREQ_EN_N")
	)
	(segment
		(start 132.89788 -43.271948)
		(end 132.669026 -43.271948)
		(width 0.12954)
		(layer "F.Cu")
		(net "M2_SSD0_CLKREQ_EN_N")
	)
	(segment
		(start 332.87335 -30.688788)
		(end 332.87335 -29.627322)
		(width 0.12954)
		(layer "F.Cu")
		(net "M2_SSD0_CLKREQ_EN_N")
	)
	(segment
		(start 132.475732 -42.49039)
		(end 134.868412 -42.49039)
		(width 0.12954)
		(layer "F.Cu")
		(net "M2_SSD0_CLKREQ_EN_N")
	)
	(segment
		(start 164.12083 -42.255948)
		(end 162.59302 -42.255948)
		(width 0.12954)
		(layer "F.Cu")
		(net "M2_SSD0_CLKREQ_EN_N")
	)
	(segment
		(start 331.936344 -27.927808)
		(end 331.936344 -27.493468)
		(width 0.12954)
		(layer "F.Cu")
		(net "M2_SSD0_CLKREQ_EN_N")
	)
	(segment
		(start 332.528418 -31.231332)
		(end 332.87335 -30.8864)
		(width 0.0889)
		(layer "F.Cu")
		(net "M2_SSD0_CLKREQ_EN_N")
	)
	(segment
		(start 332.87335 -30.8864)
		(end 332.87335 -30.688788)
		(width 0.0889)
		(layer "F.Cu")
		(net "M2_SSD0_CLKREQ_EN_N")
	)
	(via
		(at 162.59302 -42.255948)
		(size 0.508)
		(drill 0.254)
		(layers "F.Cu" "B.Cu")
		(net "M2_SSD0_CLKREQ_EN_N")
	)
	(via
		(at 132.89788 -43.271948)
		(size 0.508)
		(drill 0.254)
		(layers "F.Cu" "B.Cu")
		(net "M2_SSD0_CLKREQ_EN_N")
	)
	(via
		(at 271.07388 -36.286948)
		(size 0.508)
		(drill 0.254)
		(layers "F.Cu" "B.Cu")
		(net "M2_SSD0_CLKREQ_EN_N")
	)
	(via
		(at 331.936344 -27.493468)
		(size 0.508)
		(drill 0.254)
		(layers "F.Cu" "B.Cu")
		(net "M2_SSD0_CLKREQ_EN_N")
	)
	(segment
		(start 271.33804 -36.286948)
		(end 271.97304 -36.921948)
		(width 0.127)
		(layer "In11.Cu")
		(net "M2_SSD0_CLKREQ_EN_N")
	)
	(segment
		(start 304.93208 -32.578548)
		(end 306.17668 -31.333948)
		(width 0.127)
		(layer "In11.Cu")
		(net "M2_SSD0_CLKREQ_EN_N")
	)
	(segment
		(start 308.03088 -31.333948)
		(end 309.13578 -30.229048)
		(width 0.127)
		(layer "In11.Cu")
		(net "M2_SSD0_CLKREQ_EN_N")
	)
	(segment
		(start 324.26148 -25.085548)
		(end 327.620122 -28.44419)
		(width 0.127)
		(layer "In11.Cu")
		(net "M2_SSD0_CLKREQ_EN_N")
	)
	(segment
		(start 304.93208 -35.956748)
		(end 304.93208 -32.578548)
		(width 0.127)
		(layer "In11.Cu")
		(net "M2_SSD0_CLKREQ_EN_N")
	)
	(segment
		(start 306.17668 -31.333948)
		(end 308.03088 -31.333948)
		(width 0.127)
		(layer "In11.Cu")
		(net "M2_SSD0_CLKREQ_EN_N")
	)
	(segment
		(start 309.814214 -28.869386)
		(end 309.814214 -27.696414)
		(width 0.127)
		(layer "In11.Cu")
		(net "M2_SSD0_CLKREQ_EN_N")
	)
	(segment
		(start 327.620122 -28.44419)
		(end 330.985622 -28.44419)
		(width 0.127)
		(layer "In11.Cu")
		(net "M2_SSD0_CLKREQ_EN_N")
	)
	(segment
		(start 303.96688 -36.921948)
		(end 304.93208 -35.956748)
		(width 0.127)
		(layer "In11.Cu")
		(net "M2_SSD0_CLKREQ_EN_N")
	)
	(segment
		(start 309.13578 -29.54782)
		(end 309.814214 -28.869386)
		(width 0.127)
		(layer "In11.Cu")
		(net "M2_SSD0_CLKREQ_EN_N")
	)
	(segment
		(start 309.13578 -30.229048)
		(end 309.13578 -29.54782)
		(width 0.127)
		(layer "In11.Cu")
		(net "M2_SSD0_CLKREQ_EN_N")
	)
	(segment
		(start 311.109614 -26.401014)
		(end 317.771526 -26.401014)
		(width 0.127)
		(layer "In11.Cu")
		(net "M2_SSD0_CLKREQ_EN_N")
	)
	(segment
		(start 309.814214 -27.696414)
		(end 311.109614 -26.401014)
		(width 0.127)
		(layer "In11.Cu")
		(net "M2_SSD0_CLKREQ_EN_N")
	)
	(segment
		(start 319.086992 -25.085548)
		(end 324.26148 -25.085548)
		(width 0.127)
		(layer "In11.Cu")
		(net "M2_SSD0_CLKREQ_EN_N")
	)
	(segment
		(start 330.985622 -28.44419)
		(end 331.936344 -27.493468)
		(width 0.127)
		(layer "In11.Cu")
		(net "M2_SSD0_CLKREQ_EN_N")
	)
	(segment
		(start 271.97304 -36.921948)
		(end 303.96688 -36.921948)
		(width 0.127)
		(layer "In11.Cu")
		(net "M2_SSD0_CLKREQ_EN_N")
	)
	(segment
		(start 317.771526 -26.401014)
		(end 319.086992 -25.085548)
		(width 0.127)
		(layer "In11.Cu")
		(net "M2_SSD0_CLKREQ_EN_N")
	)
	(segment
		(start 271.07388 -36.286948)
		(end 271.33804 -36.286948)
		(width 0.127)
		(layer "In11.Cu")
		(net "M2_SSD0_CLKREQ_EN_N")
	)
	(segment
		(start 228.583744 -50.946812)
		(end 237.91926 -50.946812)
		(width 0.127)
		(layer "In13.Cu")
		(net "M2_SSD0_CLKREQ_EN_N")
	)
	(segment
		(start 241.823494 -48.626776)
		(end 242.008152 -48.442118)
		(width 0.127)
		(layer "In13.Cu")
		(net "M2_SSD0_CLKREQ_EN_N")
	)
	(segment
		(start 246.05107 -48.442118)
		(end 247.9294 -46.563788)
		(width 0.127)
		(layer "In13.Cu")
		(net "M2_SSD0_CLKREQ_EN_N")
	)
	(segment
		(start 242.008152 -48.442118)
		(end 246.05107 -48.442118)
		(width 0.127)
		(layer "In13.Cu")
		(net "M2_SSD0_CLKREQ_EN_N")
	)
	(segment
		(start 162.59302 -42.255948)
		(end 177.09388 -42.255948)
		(width 0.127)
		(layer "In13.Cu")
		(net "M2_SSD0_CLKREQ_EN_N")
	)
	(segment
		(start 223.19488 -45.557948)
		(end 228.583744 -50.946812)
		(width 0.127)
		(layer "In13.Cu")
		(net "M2_SSD0_CLKREQ_EN_N")
	)
	(segment
		(start 272.43278 -37.042344)
		(end 271.677384 -36.286948)
		(width 0.127)
		(layer "In13.Cu")
		(net "M2_SSD0_CLKREQ_EN_N")
	)
	(segment
		(start 177.72888 -41.620948)
		(end 210.74888 -41.620948)
		(width 0.127)
		(layer "In13.Cu")
		(net "M2_SSD0_CLKREQ_EN_N")
	)
	(segment
		(start 213.28888 -44.160948)
		(end 214.55888 -44.160948)
		(width 0.127)
		(layer "In13.Cu")
		(net "M2_SSD0_CLKREQ_EN_N")
	)
	(segment
		(start 255.5113 -45.837348)
		(end 265.2141 -45.837348)
		(width 0.127)
		(layer "In13.Cu")
		(net "M2_SSD0_CLKREQ_EN_N")
	)
	(segment
		(start 271.677384 -36.286948)
		(end 271.07388 -36.286948)
		(width 0.127)
		(layer "In13.Cu")
		(net "M2_SSD0_CLKREQ_EN_N")
	)
	(segment
		(start 240.860072 -51.57216)
		(end 241.823494 -50.608738)
		(width 0.127)
		(layer "In13.Cu")
		(net "M2_SSD0_CLKREQ_EN_N")
	)
	(segment
		(start 265.8618 -45.189648)
		(end 269.299944 -45.189648)
		(width 0.127)
		(layer "In13.Cu")
		(net "M2_SSD0_CLKREQ_EN_N")
	)
	(segment
		(start 272.43278 -42.056812)
		(end 272.43278 -37.042344)
		(width 0.127)
		(layer "In13.Cu")
		(net "M2_SSD0_CLKREQ_EN_N")
	)
	(segment
		(start 238.544608 -51.57216)
		(end 240.860072 -51.57216)
		(width 0.127)
		(layer "In13.Cu")
		(net "M2_SSD0_CLKREQ_EN_N")
	)
	(segment
		(start 210.74888 -41.620948)
		(end 213.28888 -44.160948)
		(width 0.127)
		(layer "In13.Cu")
		(net "M2_SSD0_CLKREQ_EN_N")
	)
	(segment
		(start 177.09388 -42.255948)
		(end 177.72888 -41.620948)
		(width 0.127)
		(layer "In13.Cu")
		(net "M2_SSD0_CLKREQ_EN_N")
	)
	(segment
		(start 215.95588 -45.557948)
		(end 223.19488 -45.557948)
		(width 0.127)
		(layer "In13.Cu")
		(net "M2_SSD0_CLKREQ_EN_N")
	)
	(segment
		(start 237.91926 -50.946812)
		(end 238.544608 -51.57216)
		(width 0.127)
		(layer "In13.Cu")
		(net "M2_SSD0_CLKREQ_EN_N")
	)
	(segment
		(start 254.78486 -46.563788)
		(end 255.5113 -45.837348)
		(width 0.127)
		(layer "In13.Cu")
		(net "M2_SSD0_CLKREQ_EN_N")
	)
	(segment
		(start 241.823494 -50.608738)
		(end 241.823494 -48.626776)
		(width 0.127)
		(layer "In13.Cu")
		(net "M2_SSD0_CLKREQ_EN_N")
	)
	(segment
		(start 247.9294 -46.563788)
		(end 254.78486 -46.563788)
		(width 0.127)
		(layer "In13.Cu")
		(net "M2_SSD0_CLKREQ_EN_N")
	)
	(segment
		(start 265.2141 -45.837348)
		(end 265.8618 -45.189648)
		(width 0.127)
		(layer "In13.Cu")
		(net "M2_SSD0_CLKREQ_EN_N")
	)
	(segment
		(start 269.299944 -45.189648)
		(end 272.43278 -42.056812)
		(width 0.127)
		(layer "In13.Cu")
		(net "M2_SSD0_CLKREQ_EN_N")
	)
	(segment
		(start 214.55888 -44.160948)
		(end 215.95588 -45.557948)
		(width 0.127)
		(layer "In13.Cu")
		(net "M2_SSD0_CLKREQ_EN_N")
	)
	(segment
		(start 156.66466 -41.783)
		(end 162.120072 -41.783)
		(width 0.127)
		(layer "In15.Cu")
		(net "M2_SSD0_CLKREQ_EN_N")
	)
	(segment
		(start 162.120072 -41.783)
		(end 162.59302 -42.255948)
		(width 0.127)
		(layer "In15.Cu")
		(net "M2_SSD0_CLKREQ_EN_N")
	)
	(segment
		(start 153.62174 -46.924468)
		(end 153.62174 -44.82592)
		(width 0.127)
		(layer "In15.Cu")
		(net "M2_SSD0_CLKREQ_EN_N")
	)
	(segment
		(start 132.89788 -43.271948)
		(end 134.1755 -44.549568)
		(width 0.127)
		(layer "In15.Cu")
		(net "M2_SSD0_CLKREQ_EN_N")
	)
	(segment
		(start 152.908 -47.638208)
		(end 153.62174 -46.924468)
		(width 0.127)
		(layer "In15.Cu")
		(net "M2_SSD0_CLKREQ_EN_N")
	)
	(segment
		(start 146.84502 -44.549568)
		(end 149.93366 -47.638208)
		(width 0.127)
		(layer "In15.Cu")
		(net "M2_SSD0_CLKREQ_EN_N")
	)
	(segment
		(start 149.93366 -47.638208)
		(end 152.908 -47.638208)
		(width 0.127)
		(layer "In15.Cu")
		(net "M2_SSD0_CLKREQ_EN_N")
	)
	(segment
		(start 153.62174 -44.82592)
		(end 156.66466 -41.783)
		(width 0.127)
		(layer "In15.Cu")
		(net "M2_SSD0_CLKREQ_EN_N")
	)
	(segment
		(start 134.1755 -44.549568)
		(end 146.84502 -44.549568)
		(width 0.127)
		(layer "In15.Cu")
		(net "M2_SSD0_CLKREQ_EN_N")
	)
	(segment
		(start 208.08188 -108.05795)
		(end 209.316828 -108.05795)
		(width 0.12954)
		(layer "F.Cu")
		(net "LED_CPU_RMCA_CATERR_R")
	)
	(segment
		(start 209.316828 -108.05795)
		(end 209.35188 -108.022898)
		(width 0.12954)
		(layer "F.Cu")
		(net "LED_CPU_RMCA_CATERR_R")
	)
	(segment
		(start 206.49184 -108.05795)
		(end 208.08188 -108.05795)
		(width 0.12954)
		(layer "F.Cu")
		(net "LED_CPU_RMCA_CATERR_R")
	)
	(via
		(at 208.08188 -108.05795)
		(size 0.762)
		(drill 0.381)
		(layers "F.Cu" "B.Cu")
		(net "LED_CPU_RMCA_CATERR_R")
	)
	(segment
		(start 207.08874 -111.7854)
		(end 207.08874 -110.7567)
		(width 0.12954)
		(layer "F.Cu")
		(net "LED_CPU_RMCA_CATERR")
	)
	(segment
		(start 205.54188 -110.057946)
		(end 206.389986 -110.057946)
		(width 0.12954)
		(layer "F.Cu")
		(net "LED_CPU_RMCA_CATERR")
	)
	(segment
		(start 195.929758 -80.617568)
		(end 195.929758 -79.791306)
		(width 0.12954)
		(layer "F.Cu")
		(net "LED_CPU_RMCA_CATERR")
	)
	(segment
		(start 194.62623 -80.627728)
		(end 194.63639 -80.617568)
		(width 0.12954)
		(layer "F.Cu")
		(net "LED_CPU_RMCA_CATERR")
	)
	(segment
		(start 194.63639 -80.617568)
		(end 195.929758 -80.617568)
		(width 0.12954)
		(layer "F.Cu")
		(net "LED_CPU_RMCA_CATERR")
	)
	(segment
		(start 206.389986 -110.057946)
		(end 207.08874 -110.7567)
		(width 0.12954)
		(layer "F.Cu")
		(net "LED_CPU_RMCA_CATERR")
	)
	(via
		(at 207.08874 -111.7854)
		(size 0.508)
		(drill 0.254)
		(layers "F.Cu" "B.Cu")
		(net "LED_CPU_RMCA_CATERR")
	)
	(via
		(at 195.929758 -79.791306)
		(size 0.508)
		(drill 0.254)
		(layers "F.Cu" "B.Cu")
		(net "LED_CPU_RMCA_CATERR")
	)
	(via
		(at 207.08874 -110.7567)
		(size 0.762)
		(drill 0.381)
		(layers "F.Cu" "B.Cu")
		(net "LED_CPU_RMCA_CATERR")
	)
	(segment
		(start 205.790292 -89.80424)
		(end 206.375 -90.388948)
		(width 0.127)
		(layer "In4.Cu")
		(net "LED_CPU_RMCA_CATERR")
	)
	(segment
		(start 206.375 -90.388948)
		(end 206.375 -92.94622)
		(width 0.127)
		(layer "In4.Cu")
		(net "LED_CPU_RMCA_CATERR")
	)
	(segment
		(start 208.1276 -109.27334)
		(end 208.1276 -111.6584)
		(width 0.127)
		(layer "In4.Cu")
		(net "LED_CPU_RMCA_CATERR")
	)
	(segment
		(start 208.0006 -111.7854)
		(end 207.08874 -111.7854)
		(width 0.127)
		(layer "In4.Cu")
		(net "LED_CPU_RMCA_CATERR")
	)
	(segment
		(start 205.790292 -88.40724)
		(end 205.790292 -89.80424)
		(width 0.127)
		(layer "In4.Cu")
		(net "LED_CPU_RMCA_CATERR")
	)
	(segment
		(start 202.81138 -103.95712)
		(end 208.1276 -109.27334)
		(width 0.127)
		(layer "In4.Cu")
		(net "LED_CPU_RMCA_CATERR")
	)
	(segment
		(start 208.1276 -111.6584)
		(end 208.0006 -111.7854)
		(width 0.127)
		(layer "In4.Cu")
		(net "LED_CPU_RMCA_CATERR")
	)
	(segment
		(start 204.96022 -94.361)
		(end 204.96022 -101.32314)
		(width 0.127)
		(layer "In4.Cu")
		(net "LED_CPU_RMCA_CATERR")
	)
	(segment
		(start 195.929758 -79.791306)
		(end 197.174358 -79.791306)
		(width 0.127)
		(layer "In4.Cu")
		(net "LED_CPU_RMCA_CATERR")
	)
	(segment
		(start 206.375 -92.94622)
		(end 204.96022 -94.361)
		(width 0.127)
		(layer "In4.Cu")
		(net "LED_CPU_RMCA_CATERR")
	)
	(segment
		(start 197.174358 -79.791306)
		(end 205.790292 -88.40724)
		(width 0.127)
		(layer "In4.Cu")
		(net "LED_CPU_RMCA_CATERR")
	)
	(segment
		(start 202.81138 -103.47198)
		(end 202.81138 -103.95712)
		(width 0.127)
		(layer "In4.Cu")
		(net "LED_CPU_RMCA_CATERR")
	)
	(segment
		(start 204.96022 -101.32314)
		(end 202.81138 -103.47198)
		(width 0.127)
		(layer "In4.Cu")
		(net "LED_CPU_RMCA_CATERR")
	)
	(segment
		(start 381.882142 -41.886378)
		(end 381.752602 -41.756838)
		(width 0.12954)
		(layer "F.Cu")
		(net "JTAG_TRC_PCH_PTI<9>")
	)
	(segment
		(start 381.752602 -43.031918)
		(end 381.752602 -42.653458)
		(width 0.12954)
		(layer "F.Cu")
		(net "JTAG_TRC_PCH_PTI<9>")
	)
	(segment
		(start 382.807718 -38.923214)
		(end 359.055162 -15.170658)
		(width 0.12954)
		(layer "F.Cu")
		(net "JTAG_TRC_PCH_PTI<9>")
	)
	(segment
		(start 385.433316 -55.249826)
		(end 383.855468 -53.671978)
		(width 0.12954)
		(layer "F.Cu")
		(net "JTAG_TRC_PCH_PTI<9>")
	)
	(segment
		(start 381.882142 -43.161458)
		(end 381.752602 -43.031918)
		(width 0.12954)
		(layer "F.Cu")
		(net "JTAG_TRC_PCH_PTI<9>")
	)
	(segment
		(start 338.624418 -37.768784)
		(end 338.787994 -38.014402)
		(width 0.0889)
		(layer "F.Cu")
		(net "JTAG_TRC_PCH_PTI<9>")
	)
	(segment
		(start 383.855468 -53.345588)
		(end 383.567686 -53.057806)
		(width 0.12954)
		(layer "F.Cu")
		(net "JTAG_TRC_PCH_PTI<9>")
	)
	(segment
		(start 382.937258 -44.670218)
		(end 383.962656 -44.670218)
		(width 0.12954)
		(layer "F.Cu")
		(net "JTAG_TRC_PCH_PTI<9>")
	)
	(segment
		(start 381.882142 -41.248838)
		(end 382.678178 -41.248838)
		(width 0.12954)
		(layer "F.Cu")
		(net "JTAG_TRC_PCH_PTI<9>")
	)
	(segment
		(start 381.752602 -40.481758)
		(end 381.752602 -40.103298)
		(width 0.12954)
		(layer "F.Cu")
		(net "JTAG_TRC_PCH_PTI<9>")
	)
	(segment
		(start 382.678178 -41.248838)
		(end 382.807718 -41.119298)
		(width 0.12954)
		(layer "F.Cu")
		(net "JTAG_TRC_PCH_PTI<9>")
	)
	(segment
		(start 338.8868 -33.41497)
		(end 338.8868 -35.875468)
		(width 0.0889)
		(layer "F.Cu")
		(net "JTAG_TRC_PCH_PTI<9>")
	)
	(segment
		(start 382.807718 -42.394378)
		(end 382.807718 -42.015918)
		(width 0.12954)
		(layer "F.Cu")
		(net "JTAG_TRC_PCH_PTI<9>")
	)
	(segment
		(start 384.092196 -44.162218)
		(end 383.962656 -44.032678)
		(width 0.12954)
		(layer "F.Cu")
		(net "JTAG_TRC_PCH_PTI<9>")
	)
	(segment
		(start 382.807718 -42.015918)
		(end 382.678178 -41.886378)
		(width 0.12954)
		(layer "F.Cu")
		(net "JTAG_TRC_PCH_PTI<9>")
	)
	(segment
		(start 382.937258 -45.307758)
		(end 382.807718 -45.178218)
		(width 0.12954)
		(layer "F.Cu")
		(net "JTAG_TRC_PCH_PTI<9>")
	)
	(segment
		(start 382.807718 -40.740838)
		(end 382.678178 -40.611298)
		(width 0.12954)
		(layer "F.Cu")
		(net "JTAG_TRC_PCH_PTI<9>")
	)
	(segment
		(start 382.807718 -46.074838)
		(end 382.937258 -45.945298)
		(width 0.12954)
		(layer "F.Cu")
		(net "JTAG_TRC_PCH_PTI<9>")
	)
	(segment
		(start 340.695788 -29.118814)
		(end 339.626956 -30.187646)
		(width 0.12954)
		(layer "F.Cu")
		(net "JTAG_TRC_PCH_PTI<9>")
	)
	(segment
		(start 338.624418 -37.477192)
		(end 338.624418 -37.768784)
		(width 0.0889)
		(layer "F.Cu")
		(net "JTAG_TRC_PCH_PTI<9>")
	)
	(segment
		(start 383.962656 -44.032678)
		(end 382.937258 -44.032678)
		(width 0.12954)
		(layer "F.Cu")
		(net "JTAG_TRC_PCH_PTI<9>")
	)
	(segment
		(start 382.678178 -43.161458)
		(end 381.882142 -43.161458)
		(width 0.12954)
		(layer "F.Cu")
		(net "JTAG_TRC_PCH_PTI<9>")
	)
	(segment
		(start 384.092196 -45.437298)
		(end 383.962656 -45.307758)
		(width 0.12954)
		(layer "F.Cu")
		(net "JTAG_TRC_PCH_PTI<9>")
	)
	(segment
		(start 340.731602 -28.276042)
		(end 340.695788 -28.362656)
		(width 0.12954)
		(layer "F.Cu")
		(net "JTAG_TRC_PCH_PTI<9>")
	)
	(segment
		(start 340.695788 -28.362656)
		(end 340.695788 -29.118814)
		(width 0.12954)
		(layer "F.Cu")
		(net "JTAG_TRC_PCH_PTI<9>")
	)
	(segment
		(start 382.678178 -41.886378)
		(end 381.882142 -41.886378)
		(width 0.12954)
		(layer "F.Cu")
		(net "JTAG_TRC_PCH_PTI<9>")
	)
	(segment
		(start 338.90077 -38.182296)
		(end 338.90077 -38.465252)
		(width 0.0889)
		(layer "F.Cu")
		(net "JTAG_TRC_PCH_PTI<9>")
	)
	(segment
		(start 381.882142 -39.973758)
		(end 382.678178 -39.973758)
		(width 0.12954)
		(layer "F.Cu")
		(net "JTAG_TRC_PCH_PTI<9>")
	)
	(segment
		(start 381.752602 -41.378378)
		(end 381.882142 -41.248838)
		(width 0.12954)
		(layer "F.Cu")
		(net "JTAG_TRC_PCH_PTI<9>")
	)
	(segment
		(start 339.257132 -30.55747)
		(end 339.257132 -33.044638)
		(width 0.0889)
		(layer "F.Cu")
		(net "JTAG_TRC_PCH_PTI<9>")
	)
	(segment
		(start 382.807718 -44.799758)
		(end 382.937258 -44.670218)
		(width 0.12954)
		(layer "F.Cu")
		(net "JTAG_TRC_PCH_PTI<9>")
	)
	(segment
		(start 383.567686 -53.057806)
		(end 383.42443 -53.05806)
		(width 0.12954)
		(layer "F.Cu")
		(net "JTAG_TRC_PCH_PTI<9>")
	)
	(segment
		(start 383.962656 -45.307758)
		(end 382.937258 -45.307758)
		(width 0.12954)
		(layer "F.Cu")
		(net "JTAG_TRC_PCH_PTI<9>")
	)
	(segment
		(start 338.787994 -38.06952)
		(end 338.90077 -38.182296)
		(width 0.0889)
		(layer "F.Cu")
		(net "JTAG_TRC_PCH_PTI<9>")
	)
	(segment
		(start 382.807718 -41.119298)
		(end 382.807718 -40.740838)
		(width 0.12954)
		(layer "F.Cu")
		(net "JTAG_TRC_PCH_PTI<9>")
	)
	(segment
		(start 338.742782 -37.074856)
		(end 338.624418 -37.477192)
		(width 0.0889)
		(layer "F.Cu")
		(net "JTAG_TRC_PCH_PTI<9>")
	)
	(segment
		(start 381.752602 -40.103298)
		(end 381.882142 -39.973758)
		(width 0.12954)
		(layer "F.Cu")
		(net "JTAG_TRC_PCH_PTI<9>")
	)
	(segment
		(start 382.807718 -52.624228)
		(end 382.807718 -46.074838)
		(width 0.12954)
		(layer "F.Cu")
		(net "JTAG_TRC_PCH_PTI<9>")
	)
	(segment
		(start 389.685276 -55.249826)
		(end 392.034776 -55.249826)
		(width 0.12954)
		(layer "F.Cu")
		(net "JTAG_TRC_PCH_PTI<9>")
	)
	(segment
		(start 382.807718 -43.903138)
		(end 382.807718 -43.290998)
		(width 0.12954)
		(layer "F.Cu")
		(net "JTAG_TRC_PCH_PTI<9>")
	)
	(segment
		(start 382.678178 -39.973758)
		(end 382.807718 -39.844218)
		(width 0.12954)
		(layer "F.Cu")
		(net "JTAG_TRC_PCH_PTI<9>")
	)
	(segment
		(start 381.882142 -42.523918)
		(end 382.678178 -42.523918)
		(width 0.12954)
		(layer "F.Cu")
		(net "JTAG_TRC_PCH_PTI<9>")
	)
	(segment
		(start 381.882142 -40.611298)
		(end 381.752602 -40.481758)
		(width 0.12954)
		(layer "F.Cu")
		(net "JTAG_TRC_PCH_PTI<9>")
	)
	(segment
		(start 382.937258 -45.945298)
		(end 383.962656 -45.945298)
		(width 0.12954)
		(layer "F.Cu")
		(net "JTAG_TRC_PCH_PTI<9>")
	)
	(segment
		(start 381.752602 -42.653458)
		(end 381.882142 -42.523918)
		(width 0.12954)
		(layer "F.Cu")
		(net "JTAG_TRC_PCH_PTI<9>")
	)
	(segment
		(start 383.24155 -53.05806)
		(end 382.807718 -52.624228)
		(width 0.12954)
		(layer "F.Cu")
		(net "JTAG_TRC_PCH_PTI<9>")
	)
	(segment
		(start 339.626956 -30.187646)
		(end 339.257132 -30.55747)
		(width 0.0889)
		(layer "F.Cu")
		(net "JTAG_TRC_PCH_PTI<9>")
	)
	(segment
		(start 382.678178 -42.523918)
		(end 382.807718 -42.394378)
		(width 0.12954)
		(layer "F.Cu")
		(net "JTAG_TRC_PCH_PTI<9>")
	)
	(segment
		(start 384.092196 -45.815758)
		(end 384.092196 -45.437298)
		(width 0.12954)
		(layer "F.Cu")
		(net "JTAG_TRC_PCH_PTI<9>")
	)
	(segment
		(start 338.742782 -36.019486)
		(end 338.742782 -37.074856)
		(width 0.0889)
		(layer "F.Cu")
		(net "JTAG_TRC_PCH_PTI<9>")
	)
	(segment
		(start 389.685276 -55.249826)
		(end 385.433316 -55.249826)
		(width 0.12954)
		(layer "F.Cu")
		(net "JTAG_TRC_PCH_PTI<9>")
	)
	(segment
		(start 382.807718 -45.178218)
		(end 382.807718 -44.799758)
		(width 0.12954)
		(layer "F.Cu")
		(net "JTAG_TRC_PCH_PTI<9>")
	)
	(segment
		(start 359.055162 -15.170658)
		(end 345.455494 -15.170658)
		(width 0.12954)
		(layer "F.Cu")
		(net "JTAG_TRC_PCH_PTI<9>")
	)
	(segment
		(start 382.937258 -44.032678)
		(end 382.807718 -43.903138)
		(width 0.12954)
		(layer "F.Cu")
		(net "JTAG_TRC_PCH_PTI<9>")
	)
	(segment
		(start 339.257132 -33.044638)
		(end 338.8868 -33.41497)
		(width 0.0889)
		(layer "F.Cu")
		(net "JTAG_TRC_PCH_PTI<9>")
	)
	(segment
		(start 383.962656 -45.945298)
		(end 384.092196 -45.815758)
		(width 0.12954)
		(layer "F.Cu")
		(net "JTAG_TRC_PCH_PTI<9>")
	)
	(segment
		(start 383.962656 -44.670218)
		(end 384.092196 -44.540678)
		(width 0.12954)
		(layer "F.Cu")
		(net "JTAG_TRC_PCH_PTI<9>")
	)
	(segment
		(start 383.42443 -53.05806)
		(end 383.24155 -53.05806)
		(width 0.12954)
		(layer "F.Cu")
		(net "JTAG_TRC_PCH_PTI<9>")
	)
	(segment
		(start 383.855468 -53.671978)
		(end 383.855468 -53.345588)
		(width 0.12954)
		(layer "F.Cu")
		(net "JTAG_TRC_PCH_PTI<9>")
	)
	(segment
		(start 340.731602 -19.89455)
		(end 340.731602 -28.276042)
		(width 0.12954)
		(layer "F.Cu")
		(net "JTAG_TRC_PCH_PTI<9>")
	)
	(segment
		(start 382.807718 -43.290998)
		(end 382.678178 -43.161458)
		(width 0.12954)
		(layer "F.Cu")
		(net "JTAG_TRC_PCH_PTI<9>")
	)
	(segment
		(start 381.752602 -41.756838)
		(end 381.752602 -41.378378)
		(width 0.12954)
		(layer "F.Cu")
		(net "JTAG_TRC_PCH_PTI<9>")
	)
	(segment
		(start 382.807718 -39.844218)
		(end 382.807718 -38.923214)
		(width 0.12954)
		(layer "F.Cu")
		(net "JTAG_TRC_PCH_PTI<9>")
	)
	(segment
		(start 338.787994 -38.014402)
		(end 338.787994 -38.06952)
		(width 0.0889)
		(layer "F.Cu")
		(net "JTAG_TRC_PCH_PTI<9>")
	)
	(segment
		(start 382.678178 -40.611298)
		(end 381.882142 -40.611298)
		(width 0.12954)
		(layer "F.Cu")
		(net "JTAG_TRC_PCH_PTI<9>")
	)
	(segment
		(start 384.092196 -44.540678)
		(end 384.092196 -44.162218)
		(width 0.12954)
		(layer "F.Cu")
		(net "JTAG_TRC_PCH_PTI<9>")
	)
	(segment
		(start 345.455494 -15.170658)
		(end 340.731602 -19.89455)
		(width 0.12954)
		(layer "F.Cu")
		(net "JTAG_TRC_PCH_PTI<9>")
	)
	(segment
		(start 338.8868 -35.875468)
		(end 338.742782 -36.019486)
		(width 0.0889)
		(layer "F.Cu")
		(net "JTAG_TRC_PCH_PTI<9>")
	)
	(via
		(at 389.685276 -55.249826)
		(size 0.508)
		(drill 0.254)
		(layers "F.Cu" "B.Cu")
		(net "JTAG_TRC_PCH_PTI<9>")
	)
	(segment
		(start 382.449578 -50.34788)
		(end 382.320038 -50.21834)
		(width 0.12954)
		(layer "F.Cu")
		(net "JTAG_TRC_PCH_PTI<8>")
	)
	(segment
		(start 381.524002 -50.85588)
		(end 382.320038 -50.85588)
		(width 0.12954)
		(layer "F.Cu")
		(net "JTAG_TRC_PCH_PTI<8>")
	)
	(segment
		(start 382.320038 -49.5808)
		(end 382.449578 -49.45126)
		(width 0.12954)
		(layer "F.Cu")
		(net "JTAG_TRC_PCH_PTI<8>")
	)
	(segment
		(start 381.524002 -48.94326)
		(end 381.394462 -48.81372)
		(width 0.12954)
		(layer "F.Cu")
		(net "JTAG_TRC_PCH_PTI<8>")
	)
	(segment
		(start 382.320038 -47.03064)
		(end 382.449578 -46.9011)
		(width 0.12954)
		(layer "F.Cu")
		(net "JTAG_TRC_PCH_PTI<8>")
	)
	(segment
		(start 381.394462 -44.98848)
		(end 381.394462 -44.61002)
		(width 0.12954)
		(layer "F.Cu")
		(net "JTAG_TRC_PCH_PTI<8>")
	)
	(segment
		(start 341.1855 -19.947636)
		(end 341.1855 -21.854668)
		(width 0.12954)
		(layer "F.Cu")
		(net "JTAG_TRC_PCH_PTI<8>")
	)
	(segment
		(start 381.524002 -50.21834)
		(end 381.394462 -50.0888)
		(width 0.12954)
		(layer "F.Cu")
		(net "JTAG_TRC_PCH_PTI<8>")
	)
	(segment
		(start 381.394462 -38.190678)
		(end 358.732582 -15.528798)
		(width 0.12954)
		(layer "F.Cu")
		(net "JTAG_TRC_PCH_PTI<8>")
	)
	(segment
		(start 382.449578 -46.9011)
		(end 382.449578 -46.52264)
		(width 0.12954)
		(layer "F.Cu")
		(net "JTAG_TRC_PCH_PTI<8>")
	)
	(segment
		(start 341.1855 -21.854668)
		(end 342.392508 -23.061676)
		(width 0.12954)
		(layer "F.Cu")
		(net "JTAG_TRC_PCH_PTI<8>")
	)
	(segment
		(start 382.320038 -47.66818)
		(end 381.524002 -47.66818)
		(width 0.12954)
		(layer "F.Cu")
		(net "JTAG_TRC_PCH_PTI<8>")
	)
	(segment
		(start 381.524002 -44.48048)
		(end 382.320038 -44.48048)
		(width 0.12954)
		(layer "F.Cu")
		(net "JTAG_TRC_PCH_PTI<8>")
	)
	(segment
		(start 381.524002 -45.75556)
		(end 382.320038 -45.75556)
		(width 0.12954)
		(layer "F.Cu")
		(net "JTAG_TRC_PCH_PTI<8>")
	)
	(segment
		(start 381.394462 -46.26356)
		(end 381.394462 -45.8851)
		(width 0.12954)
		(layer "F.Cu")
		(net "JTAG_TRC_PCH_PTI<8>")
	)
	(segment
		(start 339.228684 -38.345618)
		(end 339.40115 -38.518084)
		(width 0.0889)
		(layer "F.Cu")
		(net "JTAG_TRC_PCH_PTI<8>")
	)
	(segment
		(start 345.604338 -15.528798)
		(end 341.1855 -19.947636)
		(width 0.12954)
		(layer "F.Cu")
		(net "JTAG_TRC_PCH_PTI<8>")
	)
	(segment
		(start 339.712046 -31.80461)
		(end 339.712046 -33.325816)
		(width 0.0889)
		(layer "F.Cu")
		(net "JTAG_TRC_PCH_PTI<8>")
	)
	(segment
		(start 381.394462 -50.98542)
		(end 381.524002 -50.85588)
		(width 0.12954)
		(layer "F.Cu")
		(net "JTAG_TRC_PCH_PTI<8>")
	)
	(segment
		(start 382.449578 -45.62602)
		(end 382.449578 -45.24756)
		(width 0.12954)
		(layer "F.Cu")
		(net "JTAG_TRC_PCH_PTI<8>")
	)
	(segment
		(start 385.426458 -55.749952)
		(end 381.394462 -51.717956)
		(width 0.12954)
		(layer "F.Cu")
		(net "JTAG_TRC_PCH_PTI<8>")
	)
	(segment
		(start 381.394462 -45.8851)
		(end 381.524002 -45.75556)
		(width 0.12954)
		(layer "F.Cu")
		(net "JTAG_TRC_PCH_PTI<8>")
	)
	(segment
		(start 339.40115 -38.880034)
		(end 339.400896 -38.880288)
		(width 0.0889)
		(layer "F.Cu")
		(net "JTAG_TRC_PCH_PTI<8>")
	)
	(segment
		(start 340.424516 -31.09214)
		(end 339.837522 -31.679134)
		(width 0.12954)
		(layer "F.Cu")
		(net "JTAG_TRC_PCH_PTI<8>")
	)
	(segment
		(start 381.524002 -47.03064)
		(end 382.320038 -47.03064)
		(width 0.12954)
		(layer "F.Cu")
		(net "JTAG_TRC_PCH_PTI<8>")
	)
	(segment
		(start 339.712046 -33.325816)
		(end 339.280754 -33.757108)
		(width 0.0889)
		(layer "F.Cu")
		(net "JTAG_TRC_PCH_PTI<8>")
	)
	(segment
		(start 382.320038 -50.21834)
		(end 381.524002 -50.21834)
		(width 0.12954)
		(layer "F.Cu")
		(net "JTAG_TRC_PCH_PTI<8>")
	)
	(segment
		(start 381.394462 -51.717956)
		(end 381.394462 -50.98542)
		(width 0.12954)
		(layer "F.Cu")
		(net "JTAG_TRC_PCH_PTI<8>")
	)
	(segment
		(start 382.449578 -49.0728)
		(end 382.320038 -48.94326)
		(width 0.12954)
		(layer "F.Cu")
		(net "JTAG_TRC_PCH_PTI<8>")
	)
	(segment
		(start 382.449578 -43.97248)
		(end 382.320038 -43.84294)
		(width 0.12954)
		(layer "F.Cu")
		(net "JTAG_TRC_PCH_PTI<8>")
	)
	(segment
		(start 381.394462 -50.0888)
		(end 381.394462 -49.71034)
		(width 0.12954)
		(layer "F.Cu")
		(net "JTAG_TRC_PCH_PTI<8>")
	)
	(segment
		(start 381.524002 -48.30572)
		(end 382.320038 -48.30572)
		(width 0.12954)
		(layer "F.Cu")
		(net "JTAG_TRC_PCH_PTI<8>")
	)
	(segment
		(start 341.409528 -29.51607)
		(end 340.424516 -30.501082)
		(width 0.12954)
		(layer "F.Cu")
		(net "JTAG_TRC_PCH_PTI<8>")
	)
	(segment
		(start 340.424516 -30.501082)
		(end 340.424516 -31.09214)
		(width 0.12954)
		(layer "F.Cu")
		(net "JTAG_TRC_PCH_PTI<8>")
	)
	(segment
		(start 381.524002 -43.84294)
		(end 381.394462 -43.7134)
		(width 0.12954)
		(layer "F.Cu")
		(net "JTAG_TRC_PCH_PTI<8>")
	)
	(segment
		(start 342.392508 -24.57704)
		(end 341.464392 -25.505156)
		(width 0.12954)
		(layer "F.Cu")
		(net "JTAG_TRC_PCH_PTI<8>")
	)
	(segment
		(start 358.732582 -15.528798)
		(end 345.604338 -15.528798)
		(width 0.12954)
		(layer "F.Cu")
		(net "JTAG_TRC_PCH_PTI<8>")
	)
	(segment
		(start 381.524002 -49.5808)
		(end 382.320038 -49.5808)
		(width 0.12954)
		(layer "F.Cu")
		(net "JTAG_TRC_PCH_PTI<8>")
	)
	(segment
		(start 341.464392 -28.372308)
		(end 341.409528 -28.504896)
		(width 0.12954)
		(layer "F.Cu")
		(net "JTAG_TRC_PCH_PTI<8>")
	)
	(segment
		(start 382.320038 -45.11802)
		(end 381.524002 -45.11802)
		(width 0.12954)
		(layer "F.Cu")
		(net "JTAG_TRC_PCH_PTI<8>")
	)
	(segment
		(start 381.524002 -47.66818)
		(end 381.394462 -47.53864)
		(width 0.12954)
		(layer "F.Cu")
		(net "JTAG_TRC_PCH_PTI<8>")
	)
	(segment
		(start 381.524002 -46.3931)
		(end 381.394462 -46.26356)
		(width 0.12954)
		(layer "F.Cu")
		(net "JTAG_TRC_PCH_PTI<8>")
	)
	(segment
		(start 339.210904 -36.771072)
		(end 339.210904 -37.749226)
		(width 0.0889)
		(layer "F.Cu")
		(net "JTAG_TRC_PCH_PTI<8>")
	)
	(segment
		(start 339.099398 -37.916612)
		(end 339.099398 -38.196012)
		(width 0.0889)
		(layer "F.Cu")
		(net "JTAG_TRC_PCH_PTI<8>")
	)
	(segment
		(start 339.099398 -38.196012)
		(end 339.228684 -38.345618)
		(width 0.0889)
		(layer "F.Cu")
		(net "JTAG_TRC_PCH_PTI<8>")
	)
	(segment
		(start 339.837522 -31.679134)
		(end 339.712046 -31.80461)
		(width 0.0889)
		(layer "F.Cu")
		(net "JTAG_TRC_PCH_PTI<8>")
	)
	(segment
		(start 382.320038 -46.3931)
		(end 381.524002 -46.3931)
		(width 0.12954)
		(layer "F.Cu")
		(net "JTAG_TRC_PCH_PTI<8>")
	)
	(segment
		(start 382.449578 -48.17618)
		(end 382.449578 -47.79772)
		(width 0.12954)
		(layer "F.Cu")
		(net "JTAG_TRC_PCH_PTI<8>")
	)
	(segment
		(start 381.394462 -47.16018)
		(end 381.524002 -47.03064)
		(width 0.12954)
		(layer "F.Cu")
		(net "JTAG_TRC_PCH_PTI<8>")
	)
	(segment
		(start 381.394462 -44.61002)
		(end 381.524002 -44.48048)
		(width 0.12954)
		(layer "F.Cu")
		(net "JTAG_TRC_PCH_PTI<8>")
	)
	(segment
		(start 382.320038 -45.75556)
		(end 382.449578 -45.62602)
		(width 0.12954)
		(layer "F.Cu")
		(net "JTAG_TRC_PCH_PTI<8>")
	)
	(segment
		(start 382.320038 -44.48048)
		(end 382.449578 -44.35094)
		(width 0.12954)
		(layer "F.Cu")
		(net "JTAG_TRC_PCH_PTI<8>")
	)
	(segment
		(start 341.409528 -28.504896)
		(end 341.409528 -29.51607)
		(width 0.12954)
		(layer "F.Cu")
		(net "JTAG_TRC_PCH_PTI<8>")
	)
	(segment
		(start 381.394462 -43.7134)
		(end 381.394462 -38.190678)
		(width 0.12954)
		(layer "F.Cu")
		(net "JTAG_TRC_PCH_PTI<8>")
	)
	(segment
		(start 388.043928 -55.749952)
		(end 392.034776 -55.749952)
		(width 0.12954)
		(layer "F.Cu")
		(net "JTAG_TRC_PCH_PTI<8>")
	)
	(segment
		(start 382.320038 -48.94326)
		(end 381.524002 -48.94326)
		(width 0.12954)
		(layer "F.Cu")
		(net "JTAG_TRC_PCH_PTI<8>")
	)
	(segment
		(start 381.394462 -49.71034)
		(end 381.524002 -49.5808)
		(width 0.12954)
		(layer "F.Cu")
		(net "JTAG_TRC_PCH_PTI<8>")
	)
	(segment
		(start 381.394462 -47.53864)
		(end 381.394462 -47.16018)
		(width 0.12954)
		(layer "F.Cu")
		(net "JTAG_TRC_PCH_PTI<8>")
	)
	(segment
		(start 342.392508 -23.061676)
		(end 342.392508 -24.57704)
		(width 0.12954)
		(layer "F.Cu")
		(net "JTAG_TRC_PCH_PTI<8>")
	)
	(segment
		(start 382.320038 -50.85588)
		(end 382.449578 -50.72634)
		(width 0.12954)
		(layer "F.Cu")
		(net "JTAG_TRC_PCH_PTI<8>")
	)
	(segment
		(start 382.449578 -46.52264)
		(end 382.320038 -46.3931)
		(width 0.12954)
		(layer "F.Cu")
		(net "JTAG_TRC_PCH_PTI<8>")
	)
	(segment
		(start 339.280754 -33.757108)
		(end 339.280754 -36.701222)
		(width 0.0889)
		(layer "F.Cu")
		(net "JTAG_TRC_PCH_PTI<8>")
	)
	(segment
		(start 382.449578 -50.72634)
		(end 382.449578 -50.34788)
		(width 0.12954)
		(layer "F.Cu")
		(net "JTAG_TRC_PCH_PTI<8>")
	)
	(segment
		(start 382.449578 -47.79772)
		(end 382.320038 -47.66818)
		(width 0.12954)
		(layer "F.Cu")
		(net "JTAG_TRC_PCH_PTI<8>")
	)
	(segment
		(start 381.394462 -48.43526)
		(end 381.524002 -48.30572)
		(width 0.12954)
		(layer "F.Cu")
		(net "JTAG_TRC_PCH_PTI<8>")
	)
	(segment
		(start 339.40115 -38.518084)
		(end 339.40115 -38.880034)
		(width 0.0889)
		(layer "F.Cu")
		(net "JTAG_TRC_PCH_PTI<8>")
	)
	(segment
		(start 388.043928 -55.749952)
		(end 385.426458 -55.749952)
		(width 0.12954)
		(layer "F.Cu")
		(net "JTAG_TRC_PCH_PTI<8>")
	)
	(segment
		(start 381.394462 -48.81372)
		(end 381.394462 -48.43526)
		(width 0.12954)
		(layer "F.Cu")
		(net "JTAG_TRC_PCH_PTI<8>")
	)
	(segment
		(start 339.210904 -37.749226)
		(end 339.099398 -37.916612)
		(width 0.0889)
		(layer "F.Cu")
		(net "JTAG_TRC_PCH_PTI<8>")
	)
	(segment
		(start 382.449578 -45.24756)
		(end 382.320038 -45.11802)
		(width 0.12954)
		(layer "F.Cu")
		(net "JTAG_TRC_PCH_PTI<8>")
	)
	(segment
		(start 382.449578 -49.45126)
		(end 382.449578 -49.0728)
		(width 0.12954)
		(layer "F.Cu")
		(net "JTAG_TRC_PCH_PTI<8>")
	)
	(segment
		(start 382.320038 -48.30572)
		(end 382.449578 -48.17618)
		(width 0.12954)
		(layer "F.Cu")
		(net "JTAG_TRC_PCH_PTI<8>")
	)
	(segment
		(start 382.449578 -44.35094)
		(end 382.449578 -43.97248)
		(width 0.12954)
		(layer "F.Cu")
		(net "JTAG_TRC_PCH_PTI<8>")
	)
	(segment
		(start 341.464392 -25.505156)
		(end 341.464392 -28.372308)
		(width 0.12954)
		(layer "F.Cu")
		(net "JTAG_TRC_PCH_PTI<8>")
	)
	(segment
		(start 381.524002 -45.11802)
		(end 381.394462 -44.98848)
		(width 0.12954)
		(layer "F.Cu")
		(net "JTAG_TRC_PCH_PTI<8>")
	)
	(segment
		(start 339.280754 -36.701222)
		(end 339.210904 -36.771072)
		(width 0.0889)
		(layer "F.Cu")
		(net "JTAG_TRC_PCH_PTI<8>")
	)
	(segment
		(start 382.320038 -43.84294)
		(end 381.524002 -43.84294)
		(width 0.12954)
		(layer "F.Cu")
		(net "JTAG_TRC_PCH_PTI<8>")
	)
	(via
		(at 388.043928 -55.749952)
		(size 0.508)
		(drill 0.254)
		(layers "F.Cu" "B.Cu")
		(net "JTAG_TRC_PCH_PTI<8>")
	)
	(segment
		(start 379.060964 -48.401986)
		(end 379.060964 -48.023526)
		(width 0.12954)
		(layer "F.Cu")
		(net "JTAG_TRC_PCH_PTI<7>")
	)
	(segment
		(start 378.516642 -46.110906)
		(end 378.646182 -45.981366)
		(width 0.12954)
		(layer "F.Cu")
		(net "JTAG_TRC_PCH_PTI<7>")
	)
	(segment
		(start 378.646182 -45.981366)
		(end 378.931424 -45.981366)
		(width 0.12954)
		(layer "F.Cu")
		(net "JTAG_TRC_PCH_PTI<7>")
	)
	(segment
		(start 378.516642 -39.539672)
		(end 378.387102 -39.410132)
		(width 0.12954)
		(layer "F.Cu")
		(net "JTAG_TRC_PCH_PTI<7>")
	)
	(segment
		(start 378.516642 -43.939206)
		(end 378.516642 -43.560746)
		(width 0.12954)
		(layer "F.Cu")
		(net "JTAG_TRC_PCH_PTI<7>")
	)
	(segment
		(start 378.931424 -42.793666)
		(end 378.646182 -42.793666)
		(width 0.12954)
		(layer "F.Cu")
		(net "JTAG_TRC_PCH_PTI<7>")
	)
	(segment
		(start 378.646182 -47.893986)
		(end 378.516642 -47.764446)
		(width 0.12954)
		(layer "F.Cu")
		(net "JTAG_TRC_PCH_PTI<7>")
	)
	(segment
		(start 378.516642 -40.814752)
		(end 378.387102 -40.685212)
		(width 0.12954)
		(layer "F.Cu")
		(net "JTAG_TRC_PCH_PTI<7>")
	)
	(segment
		(start 378.516642 -38.643052)
		(end 378.516642 -37.182806)
		(width 0.12954)
		(layer "F.Cu")
		(net "JTAG_TRC_PCH_PTI<7>")
	)
	(segment
		(start 378.03836 -40.047672)
		(end 378.387102 -40.047672)
		(width 0.12954)
		(layer "F.Cu")
		(net "JTAG_TRC_PCH_PTI<7>")
	)
	(segment
		(start 377.90882 -40.177212)
		(end 378.03836 -40.047672)
		(width 0.12954)
		(layer "F.Cu")
		(net "JTAG_TRC_PCH_PTI<7>")
	)
	(segment
		(start 389.670544 -56.237632)
		(end 389.670544 -56.528462)
		(width 0.12954)
		(layer "F.Cu")
		(net "JTAG_TRC_PCH_PTI<7>")
	)
	(segment
		(start 378.387102 -39.410132)
		(end 378.03836 -39.410132)
		(width 0.12954)
		(layer "F.Cu")
		(net "JTAG_TRC_PCH_PTI<7>")
	)
	(segment
		(start 345.689682 -17.229328)
		(end 345.689682 -17.412716)
		(width 0.12954)
		(layer "F.Cu")
		(net "JTAG_TRC_PCH_PTI<7>")
	)
	(segment
		(start 378.646182 -49.169066)
		(end 378.516642 -49.039526)
		(width 0.12954)
		(layer "F.Cu")
		(net "JTAG_TRC_PCH_PTI<7>")
	)
	(segment
		(start 377.90882 -39.280592)
		(end 377.90882 -38.902132)
		(width 0.12954)
		(layer "F.Cu")
		(net "JTAG_TRC_PCH_PTI<7>")
	)
	(segment
		(start 388.903464 -56.108092)
		(end 388.525004 -56.108092)
		(width 0.12954)
		(layer "F.Cu")
		(net "JTAG_TRC_PCH_PTI<7>")
	)
	(segment
		(start 342.258396 -32.118808)
		(end 342.258396 -32.613092)
		(width 0.0889)
		(layer "F.Cu")
		(net "JTAG_TRC_PCH_PTI<7>")
	)
	(segment
		(start 387.757924 -56.528462)
		(end 387.757924 -56.237632)
		(width 0.12954)
		(layer "F.Cu")
		(net "JTAG_TRC_PCH_PTI<7>")
	)
	(segment
		(start 379.060964 -44.198286)
		(end 378.931424 -44.068746)
		(width 0.12954)
		(layer "F.Cu")
		(net "JTAG_TRC_PCH_PTI<7>")
	)
	(segment
		(start 388.525004 -56.108092)
		(end 388.395464 -56.237632)
		(width 0.12954)
		(layer "F.Cu")
		(net "JTAG_TRC_PCH_PTI<7>")
	)
	(segment
		(start 344.52052 -18.581878)
		(end 344.337132 -18.581878)
		(width 0.12954)
		(layer "F.Cu")
		(net "JTAG_TRC_PCH_PTI<7>")
	)
	(segment
		(start 344.11285 -18.540984)
		(end 343.873328 -18.780506)
		(width 0.12954)
		(layer "F.Cu")
		(net "JTAG_TRC_PCH_PTI<7>")
	)
	(segment
		(start 378.646182 -44.068746)
		(end 378.516642 -43.939206)
		(width 0.12954)
		(layer "F.Cu")
		(net "JTAG_TRC_PCH_PTI<7>")
	)
	(segment
		(start 345.197938 -17.639284)
		(end 345.01455 -17.639284)
		(width 0.12954)
		(layer "F.Cu")
		(net "JTAG_TRC_PCH_PTI<7>")
	)
	(segment
		(start 378.516642 -45.214286)
		(end 378.516642 -44.835826)
		(width 0.12954)
		(layer "F.Cu")
		(net "JTAG_TRC_PCH_PTI<7>")
	)
	(segment
		(start 378.931424 -49.806606)
		(end 379.060964 -49.677066)
		(width 0.12954)
		(layer "F.Cu")
		(net "JTAG_TRC_PCH_PTI<7>")
	)
	(segment
		(start 387.757924 -56.237632)
		(end 387.628384 -56.108092)
		(width 0.12954)
		(layer "F.Cu")
		(net "JTAG_TRC_PCH_PTI<7>")
	)
	(segment
		(start 378.931424 -45.981366)
		(end 379.060964 -45.851826)
		(width 0.12954)
		(layer "F.Cu")
		(net "JTAG_TRC_PCH_PTI<7>")
	)
	(segment
		(start 382.342898 -55.414418)
		(end 382.213358 -55.284878)
		(width 0.12954)
		(layer "F.Cu")
		(net "JTAG_TRC_PCH_PTI<7>")
	)
	(segment
		(start 378.71019 -51.45405)
		(end 378.974604 -51.189636)
		(width 0.12954)
		(layer "F.Cu")
		(net "JTAG_TRC_PCH_PTI<7>")
	)
	(segment
		(start 343.873328 -18.780506)
		(end 343.873328 -26.726896)
		(width 0.12954)
		(layer "F.Cu")
		(net "JTAG_TRC_PCH_PTI<7>")
	)
	(segment
		(start 378.646182 -42.156126)
		(end 378.931424 -42.156126)
		(width 0.12954)
		(layer "F.Cu")
		(net "JTAG_TRC_PCH_PTI<7>")
	)
	(segment
		(start 378.931424 -48.531526)
		(end 379.060964 -48.401986)
		(width 0.12954)
		(layer "F.Cu")
		(net "JTAG_TRC_PCH_PTI<7>")
	)
	(segment
		(start 384.871468 -56.108092)
		(end 384.048254 -55.284878)
		(width 0.12954)
		(layer "F.Cu")
		(net "JTAG_TRC_PCH_PTI<7>")
	)
	(segment
		(start 379.060964 -42.923206)
		(end 378.931424 -42.793666)
		(width 0.12954)
		(layer "F.Cu")
		(net "JTAG_TRC_PCH_PTI<7>")
	)
	(segment
		(start 340.401402 -37.808154)
		(end 340.401402 -38.050216)
		(width 0.0889)
		(layer "F.Cu")
		(net "JTAG_TRC_PCH_PTI<7>")
	)
	(segment
		(start 378.646182 -43.431206)
		(end 378.931424 -43.431206)
		(width 0.12954)
		(layer "F.Cu")
		(net "JTAG_TRC_PCH_PTI<7>")
	)
	(segment
		(start 378.646182 -44.706286)
		(end 378.931424 -44.706286)
		(width 0.12954)
		(layer "F.Cu")
		(net "JTAG_TRC_PCH_PTI<7>")
	)
	(segment
		(start 343.700608 -27.143964)
		(end 343.700608 -28.434538)
		(width 0.12954)
		(layer "F.Cu")
		(net "JTAG_TRC_PCH_PTI<7>")
	)
	(segment
		(start 357.937054 -16.603218)
		(end 346.050616 -16.603218)
		(width 0.12954)
		(layer "F.Cu")
		(net "JTAG_TRC_PCH_PTI<7>")
	)
	(segment
		(start 378.516642 -39.918132)
		(end 378.516642 -39.539672)
		(width 0.12954)
		(layer "F.Cu")
		(net "JTAG_TRC_PCH_PTI<7>")
	)
	(segment
		(start 377.90882 -38.902132)
		(end 378.03836 -38.772592)
		(width 0.12954)
		(layer "F.Cu")
		(net "JTAG_TRC_PCH_PTI<7>")
	)
	(segment
		(start 378.977652 -51.9049)
		(end 378.71019 -51.637438)
		(width 0.12954)
		(layer "F.Cu")
		(net "JTAG_TRC_PCH_PTI<7>")
	)
	(segment
		(start 378.516642 -44.835826)
		(end 378.646182 -44.706286)
		(width 0.12954)
		(layer "F.Cu")
		(net "JTAG_TRC_PCH_PTI<7>")
	)
	(segment
		(start 344.747088 -18.090134)
		(end 344.787982 -18.131028)
		(width 0.12954)
		(layer "F.Cu")
		(net "JTAG_TRC_PCH_PTI<7>")
	)
	(segment
		(start 345.648788 -17.005046)
		(end 345.648788 -17.188434)
		(width 0.12954)
		(layer "F.Cu")
		(net "JTAG_TRC_PCH_PTI<7>")
	)
	(segment
		(start 378.646182 -47.256446)
		(end 378.931424 -47.256446)
		(width 0.12954)
		(layer "F.Cu")
		(net "JTAG_TRC_PCH_PTI<7>")
	)
	(segment
		(start 343.198958 -28.936188)
		(end 343.198958 -31.178246)
		(width 0.12954)
		(layer "F.Cu")
		(net "JTAG_TRC_PCH_PTI<7>")
	)
	(segment
		(start 382.342898 -55.785766)
		(end 382.342898 -55.414418)
		(width 0.12954)
		(layer "F.Cu")
		(net "JTAG_TRC_PCH_PTI<7>")
	)
	(segment
		(start 344.337132 -18.581878)
		(end 344.296238 -18.540984)
		(width 0.12954)
		(layer "F.Cu")
		(net "JTAG_TRC_PCH_PTI<7>")
	)
	(segment
		(start 378.646182 -49.806606)
		(end 378.931424 -49.806606)
		(width 0.12954)
		(layer "F.Cu")
		(net "JTAG_TRC_PCH_PTI<7>")
	)
	(segment
		(start 378.931424 -47.893986)
		(end 378.646182 -47.893986)
		(width 0.12954)
		(layer "F.Cu")
		(net "JTAG_TRC_PCH_PTI<7>")
	)
	(segment
		(start 378.931424 -47.256446)
		(end 379.060964 -47.126906)
		(width 0.12954)
		(layer "F.Cu")
		(net "JTAG_TRC_PCH_PTI<7>")
	)
	(segment
		(start 378.03836 -40.685212)
		(end 377.90882 -40.555672)
		(width 0.12954)
		(layer "F.Cu")
		(net "JTAG_TRC_PCH_PTI<7>")
	)
	(segment
		(start 379.060964 -49.298606)
		(end 378.931424 -49.169066)
		(width 0.12954)
		(layer "F.Cu")
		(net "JTAG_TRC_PCH_PTI<7>")
	)
	(segment
		(start 344.787982 -18.314416)
		(end 344.52052 -18.581878)
		(width 0.12954)
		(layer "F.Cu")
		(net "JTAG_TRC_PCH_PTI<7>")
	)
	(segment
		(start 378.646182 -46.618906)
		(end 378.516642 -46.489366)
		(width 0.12954)
		(layer "F.Cu")
		(net "JTAG_TRC_PCH_PTI<7>")
	)
	(segment
		(start 345.648788 -17.188434)
		(end 345.689682 -17.229328)
		(width 0.12954)
		(layer "F.Cu")
		(net "JTAG_TRC_PCH_PTI<7>")
	)
	(segment
		(start 382.850898 -55.915306)
		(end 382.472438 -55.915306)
		(width 0.12954)
		(layer "F.Cu")
		(net "JTAG_TRC_PCH_PTI<7>")
	)
	(segment
		(start 340.402164 -37.807392)
		(end 340.401402 -37.808154)
		(width 0.0889)
		(layer "F.Cu")
		(net "JTAG_TRC_PCH_PTI<7>")
	)
	(segment
		(start 379.16104 -51.9049)
		(end 378.977652 -51.9049)
		(width 0.12954)
		(layer "F.Cu")
		(net "JTAG_TRC_PCH_PTI<7>")
	)
	(segment
		(start 379.879352 -52.8066)
		(end 379.61189 -52.539138)
		(width 0.12954)
		(layer "F.Cu")
		(net "JTAG_TRC_PCH_PTI<7>")
	)
	(segment
		(start 389.033004 -56.237632)
		(end 388.903464 -56.108092)
		(width 0.12954)
		(layer "F.Cu")
		(net "JTAG_TRC_PCH_PTI<7>")
	)
	(segment
		(start 389.162544 -56.658002)
		(end 389.033004 -56.528462)
		(width 0.12954)
		(layer "F.Cu")
		(net "JTAG_TRC_PCH_PTI<7>")
	)
	(segment
		(start 383.109978 -55.284878)
		(end 382.980438 -55.414418)
		(width 0.12954)
		(layer "F.Cu")
		(net "JTAG_TRC_PCH_PTI<7>")
	)
	(segment
		(start 379.060964 -45.473366)
		(end 378.931424 -45.343826)
		(width 0.12954)
		(layer "F.Cu")
		(net "JTAG_TRC_PCH_PTI<7>")
	)
	(segment
		(start 378.646182 -42.793666)
		(end 378.516642 -42.664126)
		(width 0.12954)
		(layer "F.Cu")
		(net "JTAG_TRC_PCH_PTI<7>")
	)
	(segment
		(start 378.646182 -45.343826)
		(end 378.516642 -45.214286)
		(width 0.12954)
		(layer "F.Cu")
		(net "JTAG_TRC_PCH_PTI<7>")
	)
	(segment
		(start 345.689682 -17.412716)
		(end 345.42222 -17.680178)
		(width 0.12954)
		(layer "F.Cu")
		(net "JTAG_TRC_PCH_PTI<7>")
	)
	(segment
		(start 377.90882 -40.555672)
		(end 377.90882 -40.177212)
		(width 0.12954)
		(layer "F.Cu")
		(net "JTAG_TRC_PCH_PTI<7>")
	)
	(segment
		(start 378.387102 -38.772592)
		(end 378.516642 -38.643052)
		(width 0.12954)
		(layer "F.Cu")
		(net "JTAG_TRC_PCH_PTI<7>")
	)
	(segment
		(start 378.516642 -37.182806)
		(end 357.937054 -16.603218)
		(width 0.12954)
		(layer "F.Cu")
		(net "JTAG_TRC_PCH_PTI<7>")
	)
	(segment
		(start 379.060964 -47.126906)
		(end 379.060964 -46.748446)
		(width 0.12954)
		(layer "F.Cu")
		(net "JTAG_TRC_PCH_PTI<7>")
	)
	(segment
		(start 379.060964 -44.576746)
		(end 379.060964 -44.198286)
		(width 0.12954)
		(layer "F.Cu")
		(net "JTAG_TRC_PCH_PTI<7>")
	)
	(segment
		(start 378.03836 -38.772592)
		(end 378.387102 -38.772592)
		(width 0.12954)
		(layer "F.Cu")
		(net "JTAG_TRC_PCH_PTI<7>")
	)
	(segment
		(start 382.472438 -55.915306)
		(end 382.342898 -55.785766)
		(width 0.12954)
		(layer "F.Cu")
		(net "JTAG_TRC_PCH_PTI<7>")
	)
	(segment
		(start 380.510542 -52.542186)
		(end 380.327154 -52.542186)
		(width 0.12954)
		(layer "F.Cu")
		(net "JTAG_TRC_PCH_PTI<7>")
	)
	(segment
		(start 384.048254 -55.284878)
		(end 383.109978 -55.284878)
		(width 0.12954)
		(layer "F.Cu")
		(net "JTAG_TRC_PCH_PTI<7>")
	)
	(segment
		(start 345.01455 -17.639284)
		(end 344.747088 -17.906746)
		(width 0.12954)
		(layer "F.Cu")
		(net "JTAG_TRC_PCH_PTI<7>")
	)
	(segment
		(start 378.646182 -41.518586)
		(end 378.516642 -41.389046)
		(width 0.12954)
		(layer "F.Cu")
		(net "JTAG_TRC_PCH_PTI<7>")
	)
	(segment
		(start 379.060964 -48.023526)
		(end 378.931424 -47.893986)
		(width 0.12954)
		(layer "F.Cu")
		(net "JTAG_TRC_PCH_PTI<7>")
	)
	(segment
		(start 378.931424 -44.706286)
		(end 379.060964 -44.576746)
		(width 0.12954)
		(layer "F.Cu")
		(net "JTAG_TRC_PCH_PTI<7>")
	)
	(segment
		(start 380.327154 -52.542186)
		(end 380.06274 -52.8066)
		(width 0.12954)
		(layer "F.Cu")
		(net "JTAG_TRC_PCH_PTI<7>")
	)
	(segment
		(start 345.238832 -17.680178)
		(end 345.197938 -17.639284)
		(width 0.12954)
		(layer "F.Cu")
		(net "JTAG_TRC_PCH_PTI<7>")
	)
	(segment
		(start 345.42222 -17.680178)
		(end 345.238832 -17.680178)
		(width 0.12954)
		(layer "F.Cu")
		(net "JTAG_TRC_PCH_PTI<7>")
	)
	(segment
		(start 392.034776 -56.249824)
		(end 390.689592 -56.249824)
		(width 0.12954)
		(layer "F.Cu")
		(net "JTAG_TRC_PCH_PTI<7>")
	)
	(segment
		(start 378.974604 -51.006248)
		(end 378.516642 -50.548286)
		(width 0.12954)
		(layer "F.Cu")
		(net "JTAG_TRC_PCH_PTI<7>")
	)
	(segment
		(start 378.387102 -40.685212)
		(end 378.03836 -40.685212)
		(width 0.12954)
		(layer "F.Cu")
		(net "JTAG_TRC_PCH_PTI<7>")
	)
	(segment
		(start 344.787982 -18.131028)
		(end 344.787982 -18.314416)
		(width 0.12954)
		(layer "F.Cu")
		(net "JTAG_TRC_PCH_PTI<7>")
	)
	(segment
		(start 382.980438 -55.414418)
		(end 382.980438 -55.785766)
		(width 0.12954)
		(layer "F.Cu")
		(net "JTAG_TRC_PCH_PTI<7>")
	)
	(segment
		(start 387.628384 -56.108092)
		(end 384.871468 -56.108092)
		(width 0.12954)
		(layer "F.Cu")
		(net "JTAG_TRC_PCH_PTI<7>")
	)
	(segment
		(start 343.700608 -28.434538)
		(end 343.198958 -28.936188)
		(width 0.12954)
		(layer "F.Cu")
		(net "JTAG_TRC_PCH_PTI<7>")
	)
	(segment
		(start 379.060964 -41.648126)
		(end 378.931424 -41.518586)
		(width 0.12954)
		(layer "F.Cu")
		(net "JTAG_TRC_PCH_PTI<7>")
	)
	(segment
		(start 380.980188 -54.854602)
		(end 380.980188 -53.65496)
		(width 0.12954)
		(layer "F.Cu")
		(net "JTAG_TRC_PCH_PTI<7>")
	)
	(segment
		(start 343.873328 -26.726896)
		(end 343.700608 -27.143964)
		(width 0.12954)
		(layer "F.Cu")
		(net "JTAG_TRC_PCH_PTI<7>")
	)
	(segment
		(start 378.516642 -47.764446)
		(end 378.516642 -47.385986)
		(width 0.12954)
		(layer "F.Cu")
		(net "JTAG_TRC_PCH_PTI<7>")
	)
	(segment
		(start 390.54786 -56.108092)
		(end 389.800084 -56.108092)
		(width 0.12954)
		(layer "F.Cu")
		(net "JTAG_TRC_PCH_PTI<7>")
	)
	(segment
		(start 389.800084 -56.108092)
		(end 389.670544 -56.237632)
		(width 0.12954)
		(layer "F.Cu")
		(net "JTAG_TRC_PCH_PTI<7>")
	)
	(segment
		(start 379.608842 -51.640486)
		(end 379.425454 -51.640486)
		(width 0.12954)
		(layer "F.Cu")
		(net "JTAG_TRC_PCH_PTI<7>")
	)
	(segment
		(start 378.516642 -50.548286)
		(end 378.516642 -49.936146)
		(width 0.12954)
		(layer "F.Cu")
		(net "JTAG_TRC_PCH_PTI<7>")
	)
	(segment
		(start 388.395464 -56.237632)
		(end 388.395464 -56.528462)
		(width 0.12954)
		(layer "F.Cu")
		(net "JTAG_TRC_PCH_PTI<7>")
	)
	(segment
		(start 378.387102 -40.047672)
		(end 378.516642 -39.918132)
		(width 0.12954)
		(layer "F.Cu")
		(net "JTAG_TRC_PCH_PTI<7>")
	)
	(segment
		(start 382.980438 -55.785766)
		(end 382.850898 -55.915306)
		(width 0.12954)
		(layer "F.Cu")
		(net "JTAG_TRC_PCH_PTI<7>")
	)
	(segment
		(start 389.541004 -56.658002)
		(end 389.162544 -56.658002)
		(width 0.12954)
		(layer "F.Cu")
		(net "JTAG_TRC_PCH_PTI<7>")
	)
	(segment
		(start 344.747088 -17.906746)
		(end 344.747088 -18.090134)
		(width 0.12954)
		(layer "F.Cu")
		(net "JTAG_TRC_PCH_PTI<7>")
	)
	(segment
		(start 379.060964 -45.851826)
		(end 379.060964 -45.473366)
		(width 0.12954)
		(layer "F.Cu")
		(net "JTAG_TRC_PCH_PTI<7>")
	)
	(segment
		(start 379.876304 -51.907948)
		(end 379.608842 -51.640486)
		(width 0.12954)
		(layer "F.Cu")
		(net "JTAG_TRC_PCH_PTI<7>")
	)
	(segment
		(start 389.033004 -56.528462)
		(end 389.033004 -56.237632)
		(width 0.12954)
		(layer "F.Cu")
		(net "JTAG_TRC_PCH_PTI<7>")
	)
	(segment
		(start 379.61189 -52.35575)
		(end 379.876304 -52.091336)
		(width 0.12954)
		(layer "F.Cu")
		(net "JTAG_TRC_PCH_PTI<7>")
	)
	(segment
		(start 342.258396 -32.613092)
		(end 340.402164 -34.469324)
		(width 0.0889)
		(layer "F.Cu")
		(net "JTAG_TRC_PCH_PTI<7>")
	)
	(segment
		(start 378.516642 -46.489366)
		(end 378.516642 -46.110906)
		(width 0.12954)
		(layer "F.Cu")
		(net "JTAG_TRC_PCH_PTI<7>")
	)
	(segment
		(start 378.516642 -49.936146)
		(end 378.646182 -49.806606)
		(width 0.12954)
		(layer "F.Cu")
		(net "JTAG_TRC_PCH_PTI<7>")
	)
	(segment
		(start 380.06274 -52.8066)
		(end 379.879352 -52.8066)
		(width 0.12954)
		(layer "F.Cu")
		(net "JTAG_TRC_PCH_PTI<7>")
	)
	(segment
		(start 379.060964 -46.748446)
		(end 378.931424 -46.618906)
		(width 0.12954)
		(layer "F.Cu")
		(net "JTAG_TRC_PCH_PTI<7>")
	)
	(segment
		(start 378.931424 -45.343826)
		(end 378.646182 -45.343826)
		(width 0.12954)
		(layer "F.Cu")
		(net "JTAG_TRC_PCH_PTI<7>")
	)
	(segment
		(start 342.415876 -31.961328)
		(end 342.258396 -32.118808)
		(width 0.0889)
		(layer "F.Cu")
		(net "JTAG_TRC_PCH_PTI<7>")
	)
	(segment
		(start 378.516642 -48.661066)
		(end 378.646182 -48.531526)
		(width 0.12954)
		(layer "F.Cu")
		(net "JTAG_TRC_PCH_PTI<7>")
	)
	(segment
		(start 378.516642 -42.664126)
		(end 378.516642 -42.285666)
		(width 0.12954)
		(layer "F.Cu")
		(net "JTAG_TRC_PCH_PTI<7>")
	)
	(segment
		(start 379.060964 -43.301666)
		(end 379.060964 -42.923206)
		(width 0.12954)
		(layer "F.Cu")
		(net "JTAG_TRC_PCH_PTI<7>")
	)
	(segment
		(start 379.425454 -51.640486)
		(end 379.16104 -51.9049)
		(width 0.12954)
		(layer "F.Cu")
		(net "JTAG_TRC_PCH_PTI<7>")
	)
	(segment
		(start 378.931424 -46.618906)
		(end 378.646182 -46.618906)
		(width 0.12954)
		(layer "F.Cu")
		(net "JTAG_TRC_PCH_PTI<7>")
	)
	(segment
		(start 378.646182 -48.531526)
		(end 378.931424 -48.531526)
		(width 0.12954)
		(layer "F.Cu")
		(net "JTAG_TRC_PCH_PTI<7>")
	)
	(segment
		(start 340.402164 -34.469324)
		(end 340.402164 -37.807392)
		(width 0.0889)
		(layer "F.Cu")
		(net "JTAG_TRC_PCH_PTI<7>")
	)
	(segment
		(start 343.198958 -31.178246)
		(end 342.415876 -31.961328)
		(width 0.12954)
		(layer "F.Cu")
		(net "JTAG_TRC_PCH_PTI<7>")
	)
	(segment
		(start 390.689592 -56.249824)
		(end 390.54786 -56.108092)
		(width 0.12954)
		(layer "F.Cu")
		(net "JTAG_TRC_PCH_PTI<7>")
	)
	(segment
		(start 378.516642 -42.285666)
		(end 378.646182 -42.156126)
		(width 0.12954)
		(layer "F.Cu")
		(net "JTAG_TRC_PCH_PTI<7>")
	)
	(segment
		(start 378.931424 -41.518586)
		(end 378.646182 -41.518586)
		(width 0.12954)
		(layer "F.Cu")
		(net "JTAG_TRC_PCH_PTI<7>")
	)
	(segment
		(start 378.516642 -47.385986)
		(end 378.646182 -47.256446)
		(width 0.12954)
		(layer "F.Cu")
		(net "JTAG_TRC_PCH_PTI<7>")
	)
	(segment
		(start 379.060964 -42.026586)
		(end 379.060964 -41.648126)
		(width 0.12954)
		(layer "F.Cu")
		(net "JTAG_TRC_PCH_PTI<7>")
	)
	(segment
		(start 380.980188 -53.011832)
		(end 380.510542 -52.542186)
		(width 0.12954)
		(layer "F.Cu")
		(net "JTAG_TRC_PCH_PTI<7>")
	)
	(segment
		(start 382.213358 -55.284878)
		(end 381.410464 -55.284878)
		(width 0.12954)
		(layer "F.Cu")
		(net "JTAG_TRC_PCH_PTI<7>")
	)
	(segment
		(start 378.03836 -39.410132)
		(end 377.90882 -39.280592)
		(width 0.12954)
		(layer "F.Cu")
		(net "JTAG_TRC_PCH_PTI<7>")
	)
	(segment
		(start 388.395464 -56.528462)
		(end 388.265924 -56.658002)
		(width 0.12954)
		(layer "F.Cu")
		(net "JTAG_TRC_PCH_PTI<7>")
	)
	(segment
		(start 378.931424 -42.156126)
		(end 379.060964 -42.026586)
		(width 0.12954)
		(layer "F.Cu")
		(net "JTAG_TRC_PCH_PTI<7>")
	)
	(segment
		(start 346.050616 -16.603218)
		(end 345.648788 -17.005046)
		(width 0.12954)
		(layer "F.Cu")
		(net "JTAG_TRC_PCH_PTI<7>")
	)
	(segment
		(start 389.670544 -56.528462)
		(end 389.541004 -56.658002)
		(width 0.12954)
		(layer "F.Cu")
		(net "JTAG_TRC_PCH_PTI<7>")
	)
	(segment
		(start 379.61189 -52.539138)
		(end 379.61189 -52.35575)
		(width 0.12954)
		(layer "F.Cu")
		(net "JTAG_TRC_PCH_PTI<7>")
	)
	(segment
		(start 378.516642 -43.560746)
		(end 378.646182 -43.431206)
		(width 0.12954)
		(layer "F.Cu")
		(net "JTAG_TRC_PCH_PTI<7>")
	)
	(segment
		(start 344.296238 -18.540984)
		(end 344.11285 -18.540984)
		(width 0.12954)
		(layer "F.Cu")
		(net "JTAG_TRC_PCH_PTI<7>")
	)
	(segment
		(start 378.974604 -51.189636)
		(end 378.974604 -51.006248)
		(width 0.12954)
		(layer "F.Cu")
		(net "JTAG_TRC_PCH_PTI<7>")
	)
	(segment
		(start 378.931424 -49.169066)
		(end 378.646182 -49.169066)
		(width 0.12954)
		(layer "F.Cu")
		(net "JTAG_TRC_PCH_PTI<7>")
	)
	(segment
		(start 378.931424 -44.068746)
		(end 378.646182 -44.068746)
		(width 0.12954)
		(layer "F.Cu")
		(net "JTAG_TRC_PCH_PTI<7>")
	)
	(segment
		(start 381.410464 -55.284878)
		(end 380.980188 -54.854602)
		(width 0.12954)
		(layer "F.Cu")
		(net "JTAG_TRC_PCH_PTI<7>")
	)
	(segment
		(start 379.060964 -49.677066)
		(end 379.060964 -49.298606)
		(width 0.12954)
		(layer "F.Cu")
		(net "JTAG_TRC_PCH_PTI<7>")
	)
	(segment
		(start 380.980188 -53.65496)
		(end 380.980188 -53.011832)
		(width 0.12954)
		(layer "F.Cu")
		(net "JTAG_TRC_PCH_PTI<7>")
	)
	(segment
		(start 379.876304 -52.091336)
		(end 379.876304 -51.907948)
		(width 0.12954)
		(layer "F.Cu")
		(net "JTAG_TRC_PCH_PTI<7>")
	)
	(segment
		(start 378.931424 -43.431206)
		(end 379.060964 -43.301666)
		(width 0.12954)
		(layer "F.Cu")
		(net "JTAG_TRC_PCH_PTI<7>")
	)
	(segment
		(start 388.265924 -56.658002)
		(end 387.887464 -56.658002)
		(width 0.12954)
		(layer "F.Cu")
		(net "JTAG_TRC_PCH_PTI<7>")
	)
	(segment
		(start 387.887464 -56.658002)
		(end 387.757924 -56.528462)
		(width 0.12954)
		(layer "F.Cu")
		(net "JTAG_TRC_PCH_PTI<7>")
	)
	(segment
		(start 378.71019 -51.637438)
		(end 378.71019 -51.45405)
		(width 0.12954)
		(layer "F.Cu")
		(net "JTAG_TRC_PCH_PTI<7>")
	)
	(segment
		(start 378.516642 -49.039526)
		(end 378.516642 -48.661066)
		(width 0.12954)
		(layer "F.Cu")
		(net "JTAG_TRC_PCH_PTI<7>")
	)
	(segment
		(start 378.516642 -41.389046)
		(end 378.516642 -40.814752)
		(width 0.12954)
		(layer "F.Cu")
		(net "JTAG_TRC_PCH_PTI<7>")
	)
	(via
		(at 380.980188 -53.65496)
		(size 0.508)
		(drill 0.254)
		(layers "F.Cu" "B.Cu")
		(net "JTAG_TRC_PCH_PTI<7>")
	)
	(segment
		(start 332.68666 -17.022572)
		(end 332.68666 -16.60525)
		(width 0.12954)
		(layer "F.Cu")
		(net "JTAG_TRC_PCH_PTI<6>")
	)
	(segment
		(start 339.753194 -37.96157)
		(end 339.753194 -38.043866)
		(width 0.0889)
		(layer "F.Cu")
		(net "JTAG_TRC_PCH_PTI<6>")
	)
	(segment
		(start 393.789662 -56.196992)
		(end 393.236704 -56.74995)
		(width 0.12954)
		(layer "F.Cu")
		(net "JTAG_TRC_PCH_PTI<6>")
	)
	(segment
		(start 339.624924 -37.41928)
		(end 339.624924 -37.768784)
		(width 0.0889)
		(layer "F.Cu")
		(net "JTAG_TRC_PCH_PTI<6>")
	)
	(segment
		(start 342.30056 -25.8953)
		(end 342.30056 -25.768808)
		(width 0.12954)
		(layer "F.Cu")
		(net "JTAG_TRC_PCH_PTI<6>")
	)
	(segment
		(start 393.789662 -55.207408)
		(end 393.789662 -56.196992)
		(width 0.12954)
		(layer "F.Cu")
		(net "JTAG_TRC_PCH_PTI<6>")
	)
	(segment
		(start 340.818216 -31.900368)
		(end 340.818216 -32.947356)
		(width 0.0889)
		(layer "F.Cu")
		(net "JTAG_TRC_PCH_PTI<6>")
	)
	(segment
		(start 339.661246 -34.104326)
		(end 339.661246 -37.295836)
		(width 0.0889)
		(layer "F.Cu")
		(net "JTAG_TRC_PCH_PTI<6>")
	)
	(segment
		(start 339.661246 -37.295836)
		(end 339.624924 -37.41928)
		(width 0.0889)
		(layer "F.Cu")
		(net "JTAG_TRC_PCH_PTI<6>")
	)
	(segment
		(start 434.029104 -44.74972)
		(end 430.266602 -44.74972)
		(width 0.12954)
		(layer "F.Cu")
		(net "JTAG_TRC_PCH_PTI<6>")
	)
	(segment
		(start 333.101696 -17.437608)
		(end 332.68666 -17.022572)
		(width 0.12954)
		(layer "F.Cu")
		(net "JTAG_TRC_PCH_PTI<6>")
	)
	(segment
		(start 342.30056 -25.8953)
		(end 342.21801 -25.97785)
		(width 0.12954)
		(layer "F.Cu")
		(net "JTAG_TRC_PCH_PTI<6>")
	)
	(segment
		(start 339.753194 -38.043866)
		(end 339.901276 -38.191948)
		(width 0.0889)
		(layer "F.Cu")
		(net "JTAG_TRC_PCH_PTI<6>")
	)
	(segment
		(start 342.125808 -29.825442)
		(end 341.237316 -30.713934)
		(width 0.12954)
		(layer "F.Cu")
		(net "JTAG_TRC_PCH_PTI<6>")
	)
	(segment
		(start 342.125808 -28.647898)
		(end 342.125808 -29.825442)
		(width 0.12954)
		(layer "F.Cu")
		(net "JTAG_TRC_PCH_PTI<6>")
	)
	(segment
		(start 340.818216 -32.947356)
		(end 339.661246 -34.104326)
		(width 0.0889)
		(layer "F.Cu")
		(net "JTAG_TRC_PCH_PTI<6>")
	)
	(segment
		(start 343.108788 -19.917156)
		(end 342.76792 -19.576288)
		(width 0.12954)
		(layer "F.Cu")
		(net "JTAG_TRC_PCH_PTI<6>")
	)
	(segment
		(start 434.336444 -44.44238)
		(end 434.029104 -44.74972)
		(width 0.12954)
		(layer "F.Cu")
		(net "JTAG_TRC_PCH_PTI<6>")
	)
	(segment
		(start 340.999826 -31.718758)
		(end 340.818216 -31.900368)
		(width 0.0889)
		(layer "F.Cu")
		(net "JTAG_TRC_PCH_PTI<6>")
	)
	(segment
		(start 430.266602 -44.74972)
		(end 430.136808 -44.619926)
		(width 0.12954)
		(layer "F.Cu")
		(net "JTAG_TRC_PCH_PTI<6>")
	)
	(segment
		(start 342.21801 -25.97785)
		(end 342.21801 -28.42514)
		(width 0.12954)
		(layer "F.Cu")
		(net "JTAG_TRC_PCH_PTI<6>")
	)
	(segment
		(start 339.901276 -38.191948)
		(end 339.901276 -38.465252)
		(width 0.0889)
		(layer "F.Cu")
		(net "JTAG_TRC_PCH_PTI<6>")
	)
	(segment
		(start 341.237316 -30.713934)
		(end 341.237316 -31.481268)
		(width 0.12954)
		(layer "F.Cu")
		(net "JTAG_TRC_PCH_PTI<6>")
	)
	(segment
		(start 393.236704 -56.74995)
		(end 392.034776 -56.74995)
		(width 0.12954)
		(layer "F.Cu")
		(net "JTAG_TRC_PCH_PTI<6>")
	)
	(segment
		(start 342.21801 -28.42514)
		(end 342.125808 -28.647898)
		(width 0.12954)
		(layer "F.Cu")
		(net "JTAG_TRC_PCH_PTI<6>")
	)
	(segment
		(start 343.108788 -24.96058)
		(end 343.108788 -19.917156)
		(width 0.12954)
		(layer "F.Cu")
		(net "JTAG_TRC_PCH_PTI<6>")
	)
	(segment
		(start 341.237316 -31.481268)
		(end 340.999826 -31.718758)
		(width 0.12954)
		(layer "F.Cu")
		(net "JTAG_TRC_PCH_PTI<6>")
	)
	(segment
		(start 339.624924 -37.768784)
		(end 339.753194 -37.96157)
		(width 0.0889)
		(layer "F.Cu")
		(net "JTAG_TRC_PCH_PTI<6>")
	)
	(segment
		(start 434.757068 -44.44238)
		(end 434.336444 -44.44238)
		(width 0.12954)
		(layer "F.Cu")
		(net "JTAG_TRC_PCH_PTI<6>")
	)
	(segment
		(start 342.30056 -25.768808)
		(end 343.108788 -24.96058)
		(width 0.12954)
		(layer "F.Cu")
		(net "JTAG_TRC_PCH_PTI<6>")
	)
	(segment
		(start 430.136808 -44.619926)
		(end 429.170084 -44.619926)
		(width 0.12954)
		(layer "F.Cu")
		(net "JTAG_TRC_PCH_PTI<6>")
	)
	(via
		(at 342.30056 -25.8953)
		(size 0.508)
		(drill 0.254)
		(layers "F.Cu" "B.Cu")
		(net "JTAG_TRC_PCH_PTI<6>")
	)
	(via
		(at 342.76792 -19.576288)
		(size 0.508)
		(drill 0.254)
		(layers "F.Cu" "B.Cu")
		(net "JTAG_TRC_PCH_PTI<6>")
	)
	(via
		(at 393.789662 -55.207408)
		(size 0.508)
		(drill 0.254)
		(layers "F.Cu" "B.Cu")
		(net "JTAG_TRC_PCH_PTI<6>")
	)
	(via
		(at 333.101696 -17.437608)
		(size 0.508)
		(drill 0.254)
		(layers "F.Cu" "B.Cu")
		(net "JTAG_TRC_PCH_PTI<6>")
	)
	(segment
		(start 340.054946 -16.863314)
		(end 333.67599 -16.863314)
		(width 0.12954)
		(layer "B.Cu")
		(net "JTAG_TRC_PCH_PTI<6>")
	)
	(segment
		(start 333.67599 -16.863314)
		(end 333.101696 -17.437608)
		(width 0.12954)
		(layer "B.Cu")
		(net "JTAG_TRC_PCH_PTI<6>")
	)
	(segment
		(start 393.39774 -44.229528)
		(end 394.351764 -43.275504)
		(width 0.12954)
		(layer "B.Cu")
		(net "JTAG_TRC_PCH_PTI<6>")
	)
	(segment
		(start 393.39774 -54.815486)
		(end 393.39774 -44.229528)
		(width 0.12954)
		(layer "B.Cu")
		(net "JTAG_TRC_PCH_PTI<6>")
	)
	(segment
		(start 427.825662 -43.275504)
		(end 429.170084 -44.619926)
		(width 0.12954)
		(layer "B.Cu")
		(net "JTAG_TRC_PCH_PTI<6>")
	)
	(segment
		(start 393.789662 -55.207408)
		(end 393.39774 -54.815486)
		(width 0.12954)
		(layer "B.Cu")
		(net "JTAG_TRC_PCH_PTI<6>")
	)
	(segment
		(start 342.76792 -19.576288)
		(end 340.054946 -16.863314)
		(width 0.12954)
		(layer "B.Cu")
		(net "JTAG_TRC_PCH_PTI<6>")
	)
	(segment
		(start 394.351764 -43.275504)
		(end 427.825662 -43.275504)
		(width 0.12954)
		(layer "B.Cu")
		(net "JTAG_TRC_PCH_PTI<6>")
	)
	(segment
		(start 363.260386 -30.72511)
		(end 355.446584 -22.911308)
		(width 0.127)
		(layer "In13.Cu")
		(net "JTAG_TRC_PCH_PTI<6>")
	)
	(segment
		(start 393.789662 -55.207408)
		(end 392.24712 -55.207408)
		(width 0.127)
		(layer "In13.Cu")
		(net "JTAG_TRC_PCH_PTI<6>")
	)
	(segment
		(start 355.446584 -22.911308)
		(end 340.971124 -16.915384)
		(width 0.127)
		(layer "In13.Cu")
		(net "JTAG_TRC_PCH_PTI<6>")
	)
	(segment
		(start 384.36296 -49.9618)
		(end 365.12627 -30.72511)
		(width 0.127)
		(layer "In13.Cu")
		(net "JTAG_TRC_PCH_PTI<6>")
	)
	(segment
		(start 392.24712 -55.207408)
		(end 388.867396 -51.827684)
		(width 0.127)
		(layer "In13.Cu")
		(net "JTAG_TRC_PCH_PTI<6>")
	)
	(segment
		(start 365.12627 -30.72511)
		(end 363.260386 -30.72511)
		(width 0.127)
		(layer "In13.Cu")
		(net "JTAG_TRC_PCH_PTI<6>")
	)
	(segment
		(start 333.62392 -16.915384)
		(end 333.101696 -17.437608)
		(width 0.127)
		(layer "In13.Cu")
		(net "JTAG_TRC_PCH_PTI<6>")
	)
	(segment
		(start 388.867396 -51.827684)
		(end 384.36296 -49.9618)
		(width 0.127)
		(layer "In13.Cu")
		(net "JTAG_TRC_PCH_PTI<6>")
	)
	(segment
		(start 340.971124 -16.915384)
		(end 333.62392 -16.915384)
		(width 0.127)
		(layer "In13.Cu")
		(net "JTAG_TRC_PCH_PTI<6>")
	)
	(segment
		(start 343.342468 -26.96845)
		(end 343.342468 -28.285948)
		(width 0.12954)
		(layer "F.Cu")
		(net "JTAG_TRC_PCH_PTI<5>")
	)
	(segment
		(start 340.22919 -38.345618)
		(end 340.401656 -38.518084)
		(width 0.0889)
		(layer "F.Cu")
		(net "JTAG_TRC_PCH_PTI<5>")
	)
	(segment
		(start 379.548644 -44.728384)
		(end 380.02972 -44.728384)
		(width 0.12954)
		(layer "F.Cu")
		(net "JTAG_TRC_PCH_PTI<5>")
	)
	(segment
		(start 379.548644 -47.916084)
		(end 379.419104 -47.786544)
		(width 0.12954)
		(layer "F.Cu")
		(net "JTAG_TRC_PCH_PTI<5>")
	)
	(segment
		(start 342.840818 -31.04642)
		(end 342.1126 -31.774638)
		(width 0.12954)
		(layer "F.Cu")
		(net "JTAG_TRC_PCH_PTI<5>")
	)
	(segment
		(start 340.401656 -38.880034)
		(end 340.401402 -38.880288)
		(width 0.0889)
		(layer "F.Cu")
		(net "JTAG_TRC_PCH_PTI<5>")
	)
	(segment
		(start 379.419104 -49.061624)
		(end 379.419104 -48.683164)
		(width 0.12954)
		(layer "F.Cu")
		(net "JTAG_TRC_PCH_PTI<5>")
	)
	(segment
		(start 379.548644 -44.090844)
		(end 379.419104 -43.961304)
		(width 0.12954)
		(layer "F.Cu")
		(net "JTAG_TRC_PCH_PTI<5>")
	)
	(segment
		(start 380.02972 -42.815764)
		(end 379.548644 -42.815764)
		(width 0.12954)
		(layer "F.Cu")
		(net "JTAG_TRC_PCH_PTI<5>")
	)
	(segment
		(start 379.548644 -38.990524)
		(end 379.419104 -38.860984)
		(width 0.12954)
		(layer "F.Cu")
		(net "JTAG_TRC_PCH_PTI<5>")
	)
	(segment
		(start 379.419104 -38.860984)
		(end 379.419104 -37.425376)
		(width 0.12954)
		(layer "F.Cu")
		(net "JTAG_TRC_PCH_PTI<5>")
	)
	(segment
		(start 379.419104 -47.408084)
		(end 379.548644 -47.278544)
		(width 0.12954)
		(layer "F.Cu")
		(net "JTAG_TRC_PCH_PTI<5>")
	)
	(segment
		(start 342.1126 -31.774638)
		(end 341.978996 -31.908242)
		(width 0.0889)
		(layer "F.Cu")
		(net "JTAG_TRC_PCH_PTI<5>")
	)
	(segment
		(start 380.15926 -49.320704)
		(end 380.02972 -49.191164)
		(width 0.12954)
		(layer "F.Cu")
		(net "JTAG_TRC_PCH_PTI<5>")
	)
	(segment
		(start 380.02972 -47.916084)
		(end 379.548644 -47.916084)
		(width 0.12954)
		(layer "F.Cu")
		(net "JTAG_TRC_PCH_PTI<5>")
	)
	(segment
		(start 380.02972 -47.278544)
		(end 380.15926 -47.149004)
		(width 0.12954)
		(layer "F.Cu")
		(net "JTAG_TRC_PCH_PTI<5>")
	)
	(segment
		(start 380.02972 -41.540684)
		(end 379.548644 -41.540684)
		(width 0.12954)
		(layer "F.Cu")
		(net "JTAG_TRC_PCH_PTI<5>")
	)
	(segment
		(start 343.342468 -28.285948)
		(end 342.840818 -28.787598)
		(width 0.12954)
		(layer "F.Cu")
		(net "JTAG_TRC_PCH_PTI<5>")
	)
	(segment
		(start 380.15926 -44.598844)
		(end 380.15926 -44.220384)
		(width 0.12954)
		(layer "F.Cu")
		(net "JTAG_TRC_PCH_PTI<5>")
	)
	(segment
		(start 380.02972 -42.178224)
		(end 380.15926 -42.048684)
		(width 0.12954)
		(layer "F.Cu")
		(net "JTAG_TRC_PCH_PTI<5>")
	)
	(segment
		(start 343.515188 -26.551382)
		(end 343.342468 -26.96845)
		(width 0.12954)
		(layer "F.Cu")
		(net "JTAG_TRC_PCH_PTI<5>")
	)
	(segment
		(start 380.02972 -40.903144)
		(end 380.15926 -40.773604)
		(width 0.12954)
		(layer "F.Cu")
		(net "JTAG_TRC_PCH_PTI<5>")
	)
	(segment
		(start 379.548644 -42.815764)
		(end 379.419104 -42.686224)
		(width 0.12954)
		(layer "F.Cu")
		(net "JTAG_TRC_PCH_PTI<5>")
	)
	(segment
		(start 380.15926 -39.498524)
		(end 380.15926 -39.120064)
		(width 0.12954)
		(layer "F.Cu")
		(net "JTAG_TRC_PCH_PTI<5>")
	)
	(segment
		(start 379.548644 -41.540684)
		(end 379.419104 -41.411144)
		(width 0.12954)
		(layer "F.Cu")
		(net "JTAG_TRC_PCH_PTI<5>")
	)
	(segment
		(start 380.02972 -38.990524)
		(end 379.548644 -38.990524)
		(width 0.12954)
		(layer "F.Cu")
		(net "JTAG_TRC_PCH_PTI<5>")
	)
	(segment
		(start 380.15926 -39.120064)
		(end 380.02972 -38.990524)
		(width 0.12954)
		(layer "F.Cu")
		(net "JTAG_TRC_PCH_PTI<5>")
	)
	(segment
		(start 380.02972 -45.365924)
		(end 379.548644 -45.365924)
		(width 0.12954)
		(layer "F.Cu")
		(net "JTAG_TRC_PCH_PTI<5>")
	)
	(segment
		(start 379.419104 -46.133004)
		(end 379.548644 -46.003464)
		(width 0.12954)
		(layer "F.Cu")
		(net "JTAG_TRC_PCH_PTI<5>")
	)
	(segment
		(start 340.18728 -37.5412)
		(end 340.17458 -37.804344)
		(width 0.0889)
		(layer "F.Cu")
		(net "JTAG_TRC_PCH_PTI<5>")
	)
	(segment
		(start 380.02972 -48.553624)
		(end 380.15926 -48.424084)
		(width 0.12954)
		(layer "F.Cu")
		(net "JTAG_TRC_PCH_PTI<5>")
	)
	(segment
		(start 340.401656 -38.518084)
		(end 340.401656 -38.880034)
		(width 0.0889)
		(layer "F.Cu")
		(net "JTAG_TRC_PCH_PTI<5>")
	)
	(segment
		(start 379.419104 -49.958244)
		(end 379.548644 -49.828704)
		(width 0.12954)
		(layer "F.Cu")
		(net "JTAG_TRC_PCH_PTI<5>")
	)
	(segment
		(start 380.15926 -47.149004)
		(end 380.15926 -46.770544)
		(width 0.12954)
		(layer "F.Cu")
		(net "JTAG_TRC_PCH_PTI<5>")
	)
	(segment
		(start 379.419104 -41.411144)
		(end 379.419104 -41.032684)
		(width 0.12954)
		(layer "F.Cu")
		(net "JTAG_TRC_PCH_PTI<5>")
	)
	(segment
		(start 381.76708 -54.813708)
		(end 381.76708 -53.104542)
		(width 0.12954)
		(layer "F.Cu")
		(net "JTAG_TRC_PCH_PTI<5>")
	)
	(segment
		(start 379.548644 -39.628064)
		(end 380.02972 -39.628064)
		(width 0.12954)
		(layer "F.Cu")
		(net "JTAG_TRC_PCH_PTI<5>")
	)
	(segment
		(start 340.17458 -37.804344)
		(end 340.099904 -37.916612)
		(width 0.0889)
		(layer "F.Cu")
		(net "JTAG_TRC_PCH_PTI<5>")
	)
	(segment
		(start 340.099904 -38.196012)
		(end 340.22919 -38.345618)
		(width 0.0889)
		(layer "F.Cu")
		(net "JTAG_TRC_PCH_PTI<5>")
	)
	(segment
		(start 379.419104 -42.307764)
		(end 379.548644 -42.178224)
		(width 0.12954)
		(layer "F.Cu")
		(net "JTAG_TRC_PCH_PTI<5>")
	)
	(segment
		(start 379.548644 -47.278544)
		(end 380.02972 -47.278544)
		(width 0.12954)
		(layer "F.Cu")
		(net "JTAG_TRC_PCH_PTI<5>")
	)
	(segment
		(start 380.02972 -44.090844)
		(end 379.548644 -44.090844)
		(width 0.12954)
		(layer "F.Cu")
		(net "JTAG_TRC_PCH_PTI<5>")
	)
	(segment
		(start 380.02972 -43.453304)
		(end 380.15926 -43.323764)
		(width 0.12954)
		(layer "F.Cu")
		(net "JTAG_TRC_PCH_PTI<5>")
	)
	(segment
		(start 379.419104 -43.582844)
		(end 379.548644 -43.453304)
		(width 0.12954)
		(layer "F.Cu")
		(net "JTAG_TRC_PCH_PTI<5>")
	)
	(segment
		(start 392.034776 -57.249822)
		(end 390.032494 -57.249822)
		(width 0.12954)
		(layer "F.Cu")
		(net "JTAG_TRC_PCH_PTI<5>")
	)
	(segment
		(start 379.419104 -43.961304)
		(end 379.419104 -43.582844)
		(width 0.12954)
		(layer "F.Cu")
		(net "JTAG_TRC_PCH_PTI<5>")
	)
	(segment
		(start 381.76708 -53.104542)
		(end 379.419104 -50.756566)
		(width 0.12954)
		(layer "F.Cu")
		(net "JTAG_TRC_PCH_PTI<5>")
	)
	(segment
		(start 380.15926 -44.220384)
		(end 380.02972 -44.090844)
		(width 0.12954)
		(layer "F.Cu")
		(net "JTAG_TRC_PCH_PTI<5>")
	)
	(segment
		(start 380.15926 -41.670224)
		(end 380.02972 -41.540684)
		(width 0.12954)
		(layer "F.Cu")
		(net "JTAG_TRC_PCH_PTI<5>")
	)
	(segment
		(start 379.419104 -50.756566)
		(end 379.419104 -49.958244)
		(width 0.12954)
		(layer "F.Cu")
		(net "JTAG_TRC_PCH_PTI<5>")
	)
	(segment
		(start 379.419104 -47.786544)
		(end 379.419104 -47.408084)
		(width 0.12954)
		(layer "F.Cu")
		(net "JTAG_TRC_PCH_PTI<5>")
	)
	(segment
		(start 380.15926 -46.770544)
		(end 380.02972 -46.641004)
		(width 0.12954)
		(layer "F.Cu")
		(net "JTAG_TRC_PCH_PTI<5>")
	)
	(segment
		(start 340.147402 -34.36366)
		(end 340.147402 -37.340032)
		(width 0.0889)
		(layer "F.Cu")
		(net "JTAG_TRC_PCH_PTI<5>")
	)
	(segment
		(start 379.548644 -45.365924)
		(end 379.419104 -45.236384)
		(width 0.12954)
		(layer "F.Cu")
		(net "JTAG_TRC_PCH_PTI<5>")
	)
	(segment
		(start 380.02972 -49.191164)
		(end 379.548644 -49.191164)
		(width 0.12954)
		(layer "F.Cu")
		(net "JTAG_TRC_PCH_PTI<5>")
	)
	(segment
		(start 379.548644 -42.178224)
		(end 380.02972 -42.178224)
		(width 0.12954)
		(layer "F.Cu")
		(net "JTAG_TRC_PCH_PTI<5>")
	)
	(segment
		(start 340.099904 -37.916612)
		(end 340.099904 -38.196012)
		(width 0.0889)
		(layer "F.Cu")
		(net "JTAG_TRC_PCH_PTI<5>")
	)
	(segment
		(start 380.02972 -44.728384)
		(end 380.15926 -44.598844)
		(width 0.12954)
		(layer "F.Cu")
		(net "JTAG_TRC_PCH_PTI<5>")
	)
	(segment
		(start 379.419104 -45.236384)
		(end 379.419104 -44.857924)
		(width 0.12954)
		(layer "F.Cu")
		(net "JTAG_TRC_PCH_PTI<5>")
	)
	(segment
		(start 379.548644 -46.003464)
		(end 380.02972 -46.003464)
		(width 0.12954)
		(layer "F.Cu")
		(net "JTAG_TRC_PCH_PTI<5>")
	)
	(segment
		(start 379.419104 -40.136064)
		(end 379.419104 -39.757604)
		(width 0.12954)
		(layer "F.Cu")
		(net "JTAG_TRC_PCH_PTI<5>")
	)
	(segment
		(start 343.515188 -18.631662)
		(end 343.515188 -26.551382)
		(width 0.12954)
		(layer "F.Cu")
		(net "JTAG_TRC_PCH_PTI<5>")
	)
	(segment
		(start 379.419104 -48.683164)
		(end 379.548644 -48.553624)
		(width 0.12954)
		(layer "F.Cu")
		(net "JTAG_TRC_PCH_PTI<5>")
	)
	(segment
		(start 379.419104 -42.686224)
		(end 379.419104 -42.307764)
		(width 0.12954)
		(layer "F.Cu")
		(net "JTAG_TRC_PCH_PTI<5>")
	)
	(segment
		(start 341.978996 -31.908242)
		(end 341.978996 -32.532066)
		(width 0.0889)
		(layer "F.Cu")
		(net "JTAG_TRC_PCH_PTI<5>")
	)
	(segment
		(start 380.02972 -49.828704)
		(end 380.15926 -49.699164)
		(width 0.12954)
		(layer "F.Cu")
		(net "JTAG_TRC_PCH_PTI<5>")
	)
	(segment
		(start 379.548644 -49.828704)
		(end 380.02972 -49.828704)
		(width 0.12954)
		(layer "F.Cu")
		(net "JTAG_TRC_PCH_PTI<5>")
	)
	(segment
		(start 380.15926 -49.699164)
		(end 380.15926 -49.320704)
		(width 0.12954)
		(layer "F.Cu")
		(net "JTAG_TRC_PCH_PTI<5>")
	)
	(segment
		(start 380.15926 -45.495464)
		(end 380.02972 -45.365924)
		(width 0.12954)
		(layer "F.Cu")
		(net "JTAG_TRC_PCH_PTI<5>")
	)
	(segment
		(start 379.419104 -41.032684)
		(end 379.548644 -40.903144)
		(width 0.12954)
		(layer "F.Cu")
		(net "JTAG_TRC_PCH_PTI<5>")
	)
	(segment
		(start 342.840818 -28.787598)
		(end 342.840818 -31.04642)
		(width 0.12954)
		(layer "F.Cu")
		(net "JTAG_TRC_PCH_PTI<5>")
	)
	(segment
		(start 379.548644 -40.903144)
		(end 380.02972 -40.903144)
		(width 0.12954)
		(layer "F.Cu")
		(net "JTAG_TRC_PCH_PTI<5>")
	)
	(segment
		(start 379.548644 -46.641004)
		(end 379.419104 -46.511464)
		(width 0.12954)
		(layer "F.Cu")
		(net "JTAG_TRC_PCH_PTI<5>")
	)
	(segment
		(start 379.419104 -44.857924)
		(end 379.548644 -44.728384)
		(width 0.12954)
		(layer "F.Cu")
		(net "JTAG_TRC_PCH_PTI<5>")
	)
	(segment
		(start 379.548644 -40.265604)
		(end 379.419104 -40.136064)
		(width 0.12954)
		(layer "F.Cu")
		(net "JTAG_TRC_PCH_PTI<5>")
	)
	(segment
		(start 379.548644 -43.453304)
		(end 380.02972 -43.453304)
		(width 0.12954)
		(layer "F.Cu")
		(net "JTAG_TRC_PCH_PTI<5>")
	)
	(segment
		(start 379.548644 -49.191164)
		(end 379.419104 -49.061624)
		(width 0.12954)
		(layer "F.Cu")
		(net "JTAG_TRC_PCH_PTI<5>")
	)
	(segment
		(start 380.15926 -42.048684)
		(end 380.15926 -41.670224)
		(width 0.12954)
		(layer "F.Cu")
		(net "JTAG_TRC_PCH_PTI<5>")
	)
	(segment
		(start 380.15926 -48.424084)
		(end 380.15926 -48.045624)
		(width 0.12954)
		(layer "F.Cu")
		(net "JTAG_TRC_PCH_PTI<5>")
	)
	(segment
		(start 379.548644 -48.553624)
		(end 380.02972 -48.553624)
		(width 0.12954)
		(layer "F.Cu")
		(net "JTAG_TRC_PCH_PTI<5>")
	)
	(segment
		(start 380.15926 -40.773604)
		(end 380.15926 -40.395144)
		(width 0.12954)
		(layer "F.Cu")
		(net "JTAG_TRC_PCH_PTI<5>")
	)
	(segment
		(start 380.15926 -42.945304)
		(end 380.02972 -42.815764)
		(width 0.12954)
		(layer "F.Cu")
		(net "JTAG_TRC_PCH_PTI<5>")
	)
	(segment
		(start 341.978996 -32.532066)
		(end 340.147402 -34.36366)
		(width 0.0889)
		(layer "F.Cu")
		(net "JTAG_TRC_PCH_PTI<5>")
	)
	(segment
		(start 380.02972 -46.641004)
		(end 379.548644 -46.641004)
		(width 0.12954)
		(layer "F.Cu")
		(net "JTAG_TRC_PCH_PTI<5>")
	)
	(segment
		(start 345.901772 -16.245078)
		(end 343.515188 -18.631662)
		(width 0.12954)
		(layer "F.Cu")
		(net "JTAG_TRC_PCH_PTI<5>")
	)
	(segment
		(start 380.02972 -46.003464)
		(end 380.15926 -45.873924)
		(width 0.12954)
		(layer "F.Cu")
		(net "JTAG_TRC_PCH_PTI<5>")
	)
	(segment
		(start 379.419104 -39.757604)
		(end 379.548644 -39.628064)
		(width 0.12954)
		(layer "F.Cu")
		(net "JTAG_TRC_PCH_PTI<5>")
	)
	(segment
		(start 380.15926 -48.045624)
		(end 380.02972 -47.916084)
		(width 0.12954)
		(layer "F.Cu")
		(net "JTAG_TRC_PCH_PTI<5>")
	)
	(segment
		(start 380.02972 -39.628064)
		(end 380.15926 -39.498524)
		(width 0.12954)
		(layer "F.Cu")
		(net "JTAG_TRC_PCH_PTI<5>")
	)
	(segment
		(start 380.15926 -43.323764)
		(end 380.15926 -42.945304)
		(width 0.12954)
		(layer "F.Cu")
		(net "JTAG_TRC_PCH_PTI<5>")
	)
	(segment
		(start 380.15926 -45.873924)
		(end 380.15926 -45.495464)
		(width 0.12954)
		(layer "F.Cu")
		(net "JTAG_TRC_PCH_PTI<5>")
	)
	(segment
		(start 358.238806 -16.245078)
		(end 345.901772 -16.245078)
		(width 0.12954)
		(layer "F.Cu")
		(net "JTAG_TRC_PCH_PTI<5>")
	)
	(segment
		(start 379.419104 -37.425376)
		(end 358.238806 -16.245078)
		(width 0.12954)
		(layer "F.Cu")
		(net "JTAG_TRC_PCH_PTI<5>")
	)
	(segment
		(start 379.419104 -46.511464)
		(end 379.419104 -46.133004)
		(width 0.12954)
		(layer "F.Cu")
		(net "JTAG_TRC_PCH_PTI<5>")
	)
	(segment
		(start 380.15926 -40.395144)
		(end 380.02972 -40.265604)
		(width 0.12954)
		(layer "F.Cu")
		(net "JTAG_TRC_PCH_PTI<5>")
	)
	(segment
		(start 340.147402 -37.340032)
		(end 340.18728 -37.5412)
		(width 0.0889)
		(layer "F.Cu")
		(net "JTAG_TRC_PCH_PTI<5>")
	)
	(segment
		(start 380.02972 -40.265604)
		(end 379.548644 -40.265604)
		(width 0.12954)
		(layer "F.Cu")
		(net "JTAG_TRC_PCH_PTI<5>")
	)
	(via
		(at 381.76708 -54.813708)
		(size 0.508)
		(drill 0.254)
		(layers "F.Cu" "B.Cu")
		(net "JTAG_TRC_PCH_PTI<5>")
	)
	(via
		(at 390.032494 -57.249822)
		(size 0.508)
		(drill 0.254)
		(layers "F.Cu" "B.Cu")
		(net "JTAG_TRC_PCH_PTI<5>")
	)
	(segment
		(start 389.363458 -56.580786)
		(end 390.032494 -57.249822)
		(width 0.12954)
		(layer "B.Cu")
		(net "JTAG_TRC_PCH_PTI<5>")
	)
	(segment
		(start 381.76708 -54.813708)
		(end 381.76708 -55.580788)
		(width 0.12954)
		(layer "B.Cu")
		(net "JTAG_TRC_PCH_PTI<5>")
	)
	(segment
		(start 382.767078 -56.580786)
		(end 389.363458 -56.580786)
		(width 0.12954)
		(layer "B.Cu")
		(net "JTAG_TRC_PCH_PTI<5>")
	)
	(segment
		(start 381.76708 -55.580788)
		(end 382.767078 -56.580786)
		(width 0.12954)
		(layer "B.Cu")
		(net "JTAG_TRC_PCH_PTI<5>")
	)
	(segment
		(start 373.989854 -34.769044)
		(end 373.989854 -34.585656)
		(width 0.12954)
		(layer "F.Cu")
		(net "JTAG_TRC_PCH_PTI<4>")
	)
	(segment
		(start 373.607584 -34.066226)
		(end 373.539004 -34.134806)
		(width 0.12954)
		(layer "F.Cu")
		(net "JTAG_TRC_PCH_PTI<4>")
	)
	(segment
		(start 374.058434 -34.333688)
		(end 373.790972 -34.066226)
		(width 0.12954)
		(layer "F.Cu")
		(net "JTAG_TRC_PCH_PTI<4>")
	)
	(segment
		(start 376.53722 -52.927758)
		(end 376.53722 -36.812474)
		(width 0.12954)
		(layer "F.Cu")
		(net "JTAG_TRC_PCH_PTI<4>")
	)
	(segment
		(start 370.184172 -30.459426)
		(end 370.000784 -30.459426)
		(width 0.12954)
		(layer "F.Cu")
		(net "JTAG_TRC_PCH_PTI<4>")
	)
	(segment
		(start 341.402162 -37.832792)
		(end 341.401908 -37.832792)
		(width 0.0889)
		(layer "F.Cu")
		(net "JTAG_TRC_PCH_PTI<4>")
	)
	(segment
		(start 389.00354 -57.749948)
		(end 392.034776 -57.749948)
		(width 0.12954)
		(layer "F.Cu")
		(net "JTAG_TRC_PCH_PTI<4>")
	)
	(segment
		(start 380.88697 -57.277508)
		(end 376.53722 -52.927758)
		(width 0.12954)
		(layer "F.Cu")
		(net "JTAG_TRC_PCH_PTI<4>")
	)
	(segment
		(start 374.891554 -35.487356)
		(end 374.960134 -35.418776)
		(width 0.12954)
		(layer "F.Cu")
		(net "JTAG_TRC_PCH_PTI<4>")
	)
	(segment
		(start 344.298778 -31.777686)
		(end 342.027256 -34.049208)
		(width 0.12954)
		(layer "F.Cu")
		(net "JTAG_TRC_PCH_PTI<4>")
	)
	(segment
		(start 367.746534 -28.021788)
		(end 358.09174 -18.366994)
		(width 0.12954)
		(layer "F.Cu")
		(net "JTAG_TRC_PCH_PTI<4>")
	)
	(segment
		(start 370.650516 -31.429706)
		(end 370.383054 -31.162244)
		(width 0.12954)
		(layer "F.Cu")
		(net "JTAG_TRC_PCH_PTI<4>")
	)
	(segment
		(start 373.088154 -33.683956)
		(end 373.156734 -33.615376)
		(width 0.12954)
		(layer "F.Cu")
		(net "JTAG_TRC_PCH_PTI<4>")
	)
	(segment
		(start 374.257316 -35.036506)
		(end 373.989854 -34.769044)
		(width 0.12954)
		(layer "F.Cu")
		(net "JTAG_TRC_PCH_PTI<4>")
	)
	(segment
		(start 371.987572 -32.262826)
		(end 371.804184 -32.262826)
		(width 0.12954)
		(layer "F.Cu")
		(net "JTAG_TRC_PCH_PTI<4>")
	)
	(segment
		(start 371.284754 -31.880556)
		(end 371.353334 -31.811976)
		(width 0.12954)
		(layer "F.Cu")
		(net "JTAG_TRC_PCH_PTI<4>")
	)
	(segment
		(start 374.058434 -34.517076)
		(end 374.058434 -34.333688)
		(width 0.12954)
		(layer "F.Cu")
		(net "JTAG_TRC_PCH_PTI<4>")
	)
	(segment
		(start 344.298778 -29.388308)
		(end 344.298778 -31.777686)
		(width 0.12954)
		(layer "F.Cu")
		(net "JTAG_TRC_PCH_PTI<4>")
	)
	(segment
		(start 341.402162 -36.634928)
		(end 341.402162 -37.832792)
		(width 0.0889)
		(layer "F.Cu")
		(net "JTAG_TRC_PCH_PTI<4>")
	)
	(segment
		(start 368.648234 -28.923488)
		(end 368.380772 -28.656026)
		(width 0.12954)
		(layer "F.Cu")
		(net "JTAG_TRC_PCH_PTI<4>")
	)
	(segment
		(start 369.099084 -29.557726)
		(end 369.030504 -29.626306)
		(width 0.12954)
		(layer "F.Cu")
		(net "JTAG_TRC_PCH_PTI<4>")
	)
	(segment
		(start 370.902484 -31.361126)
		(end 370.833904 -31.429706)
		(width 0.12954)
		(layer "F.Cu")
		(net "JTAG_TRC_PCH_PTI<4>")
	)
	(segment
		(start 369.549934 -29.825188)
		(end 369.282472 -29.557726)
		(width 0.12954)
		(layer "F.Cu")
		(net "JTAG_TRC_PCH_PTI<4>")
	)
	(segment
		(start 371.353334 -31.811976)
		(end 371.353334 -31.628588)
		(width 0.12954)
		(layer "F.Cu")
		(net "JTAG_TRC_PCH_PTI<4>")
	)
	(segment
		(start 371.284754 -32.063944)
		(end 371.284754 -31.880556)
		(width 0.12954)
		(layer "F.Cu")
		(net "JTAG_TRC_PCH_PTI<4>")
	)
	(segment
		(start 373.790972 -34.066226)
		(end 373.607584 -34.066226)
		(width 0.12954)
		(layer "F.Cu")
		(net "JTAG_TRC_PCH_PTI<4>")
	)
	(segment
		(start 375.410984 -35.869626)
		(end 375.342404 -35.938206)
		(width 0.12954)
		(layer "F.Cu")
		(net "JTAG_TRC_PCH_PTI<4>")
	)
	(segment
		(start 375.159016 -35.938206)
		(end 374.891554 -35.670744)
		(width 0.12954)
		(layer "F.Cu")
		(net "JTAG_TRC_PCH_PTI<4>")
	)
	(segment
		(start 368.579654 -29.175456)
		(end 368.648234 -29.106876)
		(width 0.12954)
		(layer "F.Cu")
		(net "JTAG_TRC_PCH_PTI<4>")
	)
	(segment
		(start 373.539004 -34.134806)
		(end 373.355616 -34.134806)
		(width 0.12954)
		(layer "F.Cu")
		(net "JTAG_TRC_PCH_PTI<4>")
	)
	(segment
		(start 371.353334 -31.628588)
		(end 371.085872 -31.361126)
		(width 0.12954)
		(layer "F.Cu")
		(net "JTAG_TRC_PCH_PTI<4>")
	)
	(segment
		(start 370.451634 -30.726888)
		(end 370.184172 -30.459426)
		(width 0.12954)
		(layer "F.Cu")
		(net "JTAG_TRC_PCH_PTI<4>")
	)
	(segment
		(start 371.552216 -32.331406)
		(end 371.284754 -32.063944)
		(width 0.12954)
		(layer "F.Cu")
		(net "JTAG_TRC_PCH_PTI<4>")
	)
	(segment
		(start 369.549934 -30.008576)
		(end 369.549934 -29.825188)
		(width 0.12954)
		(layer "F.Cu")
		(net "JTAG_TRC_PCH_PTI<4>")
	)
	(segment
		(start 369.481354 -30.077156)
		(end 369.549934 -30.008576)
		(width 0.12954)
		(layer "F.Cu")
		(net "JTAG_TRC_PCH_PTI<4>")
	)
	(segment
		(start 375.342404 -35.938206)
		(end 375.159016 -35.938206)
		(width 0.12954)
		(layer "F.Cu")
		(net "JTAG_TRC_PCH_PTI<4>")
	)
	(segment
		(start 372.186454 -32.965644)
		(end 372.186454 -32.782256)
		(width 0.12954)
		(layer "F.Cu")
		(net "JTAG_TRC_PCH_PTI<4>")
	)
	(segment
		(start 371.804184 -32.262826)
		(end 371.735604 -32.331406)
		(width 0.12954)
		(layer "F.Cu")
		(net "JTAG_TRC_PCH_PTI<4>")
	)
	(segment
		(start 368.128804 -28.724606)
		(end 367.945416 -28.724606)
		(width 0.12954)
		(layer "F.Cu")
		(net "JTAG_TRC_PCH_PTI<4>")
	)
	(segment
		(start 367.945416 -28.724606)
		(end 367.677954 -28.457144)
		(width 0.12954)
		(layer "F.Cu")
		(net "JTAG_TRC_PCH_PTI<4>")
	)
	(segment
		(start 358.09174 -18.366994)
		(end 346.70238 -18.366994)
		(width 0.12954)
		(layer "F.Cu")
		(net "JTAG_TRC_PCH_PTI<4>")
	)
	(segment
		(start 369.481354 -30.260544)
		(end 369.481354 -30.077156)
		(width 0.12954)
		(layer "F.Cu")
		(net "JTAG_TRC_PCH_PTI<4>")
	)
	(segment
		(start 341.762842 -36.274248)
		(end 341.402162 -36.634928)
		(width 0.0889)
		(layer "F.Cu")
		(net "JTAG_TRC_PCH_PTI<4>")
	)
	(segment
		(start 381.46736 -57.277508)
		(end 380.88697 -57.277508)
		(width 0.12954)
		(layer "F.Cu")
		(net "JTAG_TRC_PCH_PTI<4>")
	)
	(segment
		(start 368.847116 -29.626306)
		(end 368.579654 -29.358844)
		(width 0.12954)
		(layer "F.Cu")
		(net "JTAG_TRC_PCH_PTI<4>")
	)
	(segment
		(start 369.030504 -29.626306)
		(end 368.847116 -29.626306)
		(width 0.12954)
		(layer "F.Cu")
		(net "JTAG_TRC_PCH_PTI<4>")
	)
	(segment
		(start 372.705884 -33.164526)
		(end 372.637304 -33.233106)
		(width 0.12954)
		(layer "F.Cu")
		(net "JTAG_TRC_PCH_PTI<4>")
	)
	(segment
		(start 368.579654 -29.358844)
		(end 368.579654 -29.175456)
		(width 0.12954)
		(layer "F.Cu")
		(net "JTAG_TRC_PCH_PTI<4>")
	)
	(segment
		(start 341.762842 -34.313622)
		(end 341.762842 -36.274248)
		(width 0.0889)
		(layer "F.Cu")
		(net "JTAG_TRC_PCH_PTI<4>")
	)
	(segment
		(start 372.889272 -33.164526)
		(end 372.705884 -33.164526)
		(width 0.12954)
		(layer "F.Cu")
		(net "JTAG_TRC_PCH_PTI<4>")
	)
	(segment
		(start 370.000784 -30.459426)
		(end 369.932204 -30.528006)
		(width 0.12954)
		(layer "F.Cu")
		(net "JTAG_TRC_PCH_PTI<4>")
	)
	(segment
		(start 369.748816 -30.528006)
		(end 369.481354 -30.260544)
		(width 0.12954)
		(layer "F.Cu")
		(net "JTAG_TRC_PCH_PTI<4>")
	)
	(segment
		(start 370.451634 -30.910276)
		(end 370.451634 -30.726888)
		(width 0.12954)
		(layer "F.Cu")
		(net "JTAG_TRC_PCH_PTI<4>")
	)
	(segment
		(start 374.960134 -35.235388)
		(end 374.692672 -34.967926)
		(width 0.12954)
		(layer "F.Cu")
		(net "JTAG_TRC_PCH_PTI<4>")
	)
	(segment
		(start 374.692672 -34.967926)
		(end 374.509284 -34.967926)
		(width 0.12954)
		(layer "F.Cu")
		(net "JTAG_TRC_PCH_PTI<4>")
	)
	(segment
		(start 369.932204 -30.528006)
		(end 369.748816 -30.528006)
		(width 0.12954)
		(layer "F.Cu")
		(net "JTAG_TRC_PCH_PTI<4>")
	)
	(segment
		(start 374.891554 -35.670744)
		(end 374.891554 -35.487356)
		(width 0.12954)
		(layer "F.Cu")
		(net "JTAG_TRC_PCH_PTI<4>")
	)
	(segment
		(start 346.70238 -18.366994)
		(end 344.958162 -20.111212)
		(width 0.12954)
		(layer "F.Cu")
		(net "JTAG_TRC_PCH_PTI<4>")
	)
	(segment
		(start 371.085872 -31.361126)
		(end 370.902484 -31.361126)
		(width 0.12954)
		(layer "F.Cu")
		(net "JTAG_TRC_PCH_PTI<4>")
	)
	(segment
		(start 373.088154 -33.867344)
		(end 373.088154 -33.683956)
		(width 0.12954)
		(layer "F.Cu")
		(net "JTAG_TRC_PCH_PTI<4>")
	)
	(segment
		(start 344.779854 -27.347164)
		(end 344.779854 -28.907232)
		(width 0.12954)
		(layer "F.Cu")
		(net "JTAG_TRC_PCH_PTI<4>")
	)
	(segment
		(start 371.735604 -32.331406)
		(end 371.552216 -32.331406)
		(width 0.12954)
		(layer "F.Cu")
		(net "JTAG_TRC_PCH_PTI<4>")
	)
	(segment
		(start 344.958162 -26.91638)
		(end 344.779854 -27.347164)
		(width 0.12954)
		(layer "F.Cu")
		(net "JTAG_TRC_PCH_PTI<4>")
	)
	(segment
		(start 372.186454 -32.782256)
		(end 372.255034 -32.713676)
		(width 0.12954)
		(layer "F.Cu")
		(net "JTAG_TRC_PCH_PTI<4>")
	)
	(segment
		(start 373.989854 -34.585656)
		(end 374.058434 -34.517076)
		(width 0.12954)
		(layer "F.Cu")
		(net "JTAG_TRC_PCH_PTI<4>")
	)
	(segment
		(start 373.156734 -33.431988)
		(end 372.889272 -33.164526)
		(width 0.12954)
		(layer "F.Cu")
		(net "JTAG_TRC_PCH_PTI<4>")
	)
	(segment
		(start 367.677954 -28.457144)
		(end 367.677954 -28.273756)
		(width 0.12954)
		(layer "F.Cu")
		(net "JTAG_TRC_PCH_PTI<4>")
	)
	(segment
		(start 388.53618 -57.282588)
		(end 389.00354 -57.749948)
		(width 0.12954)
		(layer "F.Cu")
		(net "JTAG_TRC_PCH_PTI<4>")
	)
	(segment
		(start 375.594372 -35.869626)
		(end 375.410984 -35.869626)
		(width 0.12954)
		(layer "F.Cu")
		(net "JTAG_TRC_PCH_PTI<4>")
	)
	(segment
		(start 374.440704 -35.036506)
		(end 374.257316 -35.036506)
		(width 0.12954)
		(layer "F.Cu")
		(net "JTAG_TRC_PCH_PTI<4>")
	)
	(segment
		(start 341.401908 -37.832792)
		(end 341.401908 -38.050216)
		(width 0.0889)
		(layer "F.Cu")
		(net "JTAG_TRC_PCH_PTI<4>")
	)
	(segment
		(start 372.255034 -32.713676)
		(end 372.255034 -32.530288)
		(width 0.12954)
		(layer "F.Cu")
		(net "JTAG_TRC_PCH_PTI<4>")
	)
	(segment
		(start 368.380772 -28.656026)
		(end 368.197384 -28.656026)
		(width 0.12954)
		(layer "F.Cu")
		(net "JTAG_TRC_PCH_PTI<4>")
	)
	(segment
		(start 367.746534 -28.205176)
		(end 367.746534 -28.021788)
		(width 0.12954)
		(layer "F.Cu")
		(net "JTAG_TRC_PCH_PTI<4>")
	)
	(segment
		(start 374.960134 -35.418776)
		(end 374.960134 -35.235388)
		(width 0.12954)
		(layer "F.Cu")
		(net "JTAG_TRC_PCH_PTI<4>")
	)
	(segment
		(start 373.156734 -33.615376)
		(end 373.156734 -33.431988)
		(width 0.12954)
		(layer "F.Cu")
		(net "JTAG_TRC_PCH_PTI<4>")
	)
	(segment
		(start 376.53722 -36.812474)
		(end 375.594372 -35.869626)
		(width 0.12954)
		(layer "F.Cu")
		(net "JTAG_TRC_PCH_PTI<4>")
	)
	(segment
		(start 372.255034 -32.530288)
		(end 371.987572 -32.262826)
		(width 0.12954)
		(layer "F.Cu")
		(net "JTAG_TRC_PCH_PTI<4>")
	)
	(segment
		(start 342.027256 -34.049208)
		(end 341.762842 -34.313622)
		(width 0.0889)
		(layer "F.Cu")
		(net "JTAG_TRC_PCH_PTI<4>")
	)
	(segment
		(start 368.197384 -28.656026)
		(end 368.128804 -28.724606)
		(width 0.12954)
		(layer "F.Cu")
		(net "JTAG_TRC_PCH_PTI<4>")
	)
	(segment
		(start 372.637304 -33.233106)
		(end 372.453916 -33.233106)
		(width 0.12954)
		(layer "F.Cu")
		(net "JTAG_TRC_PCH_PTI<4>")
	)
	(segment
		(start 368.648234 -29.106876)
		(end 368.648234 -28.923488)
		(width 0.12954)
		(layer "F.Cu")
		(net "JTAG_TRC_PCH_PTI<4>")
	)
	(segment
		(start 370.383054 -30.978856)
		(end 370.451634 -30.910276)
		(width 0.12954)
		(layer "F.Cu")
		(net "JTAG_TRC_PCH_PTI<4>")
	)
	(segment
		(start 369.282472 -29.557726)
		(end 369.099084 -29.557726)
		(width 0.12954)
		(layer "F.Cu")
		(net "JTAG_TRC_PCH_PTI<4>")
	)
	(segment
		(start 370.383054 -31.162244)
		(end 370.383054 -30.978856)
		(width 0.12954)
		(layer "F.Cu")
		(net "JTAG_TRC_PCH_PTI<4>")
	)
	(segment
		(start 373.355616 -34.134806)
		(end 373.088154 -33.867344)
		(width 0.12954)
		(layer "F.Cu")
		(net "JTAG_TRC_PCH_PTI<4>")
	)
	(segment
		(start 372.453916 -33.233106)
		(end 372.186454 -32.965644)
		(width 0.12954)
		(layer "F.Cu")
		(net "JTAG_TRC_PCH_PTI<4>")
	)
	(segment
		(start 367.677954 -28.273756)
		(end 367.746534 -28.205176)
		(width 0.12954)
		(layer "F.Cu")
		(net "JTAG_TRC_PCH_PTI<4>")
	)
	(segment
		(start 344.958162 -20.111212)
		(end 344.958162 -26.91638)
		(width 0.12954)
		(layer "F.Cu")
		(net "JTAG_TRC_PCH_PTI<4>")
	)
	(segment
		(start 344.779854 -28.907232)
		(end 344.298778 -29.388308)
		(width 0.12954)
		(layer "F.Cu")
		(net "JTAG_TRC_PCH_PTI<4>")
	)
	(segment
		(start 370.833904 -31.429706)
		(end 370.650516 -31.429706)
		(width 0.12954)
		(layer "F.Cu")
		(net "JTAG_TRC_PCH_PTI<4>")
	)
	(segment
		(start 374.509284 -34.967926)
		(end 374.440704 -35.036506)
		(width 0.12954)
		(layer "F.Cu")
		(net "JTAG_TRC_PCH_PTI<4>")
	)
	(via
		(at 388.53618 -57.282588)
		(size 0.508)
		(drill 0.254)
		(layers "F.Cu" "B.Cu")
		(net "JTAG_TRC_PCH_PTI<4>")
	)
	(via
		(at 381.46736 -57.277508)
		(size 0.508)
		(drill 0.254)
		(layers "F.Cu" "B.Cu")
		(net "JTAG_TRC_PCH_PTI<4>")
	)
	(segment
		(start 385.690618 -57.966864)
		(end 385.690618 -60.575444)
		(width 0.12954)
		(layer "B.Cu")
		(net "JTAG_TRC_PCH_PTI<4>")
	)
	(segment
		(start 386.836158 -57.837324)
		(end 386.965698 -57.966864)
		(width 0.12954)
		(layer "B.Cu")
		(net "JTAG_TRC_PCH_PTI<4>")
	)
	(segment
		(start 381.46736 -57.277508)
		(end 382.027176 -57.837324)
		(width 0.12954)
		(layer "B.Cu")
		(net "JTAG_TRC_PCH_PTI<4>")
	)
	(segment
		(start 387.473698 -60.704984)
		(end 387.603238 -60.575444)
		(width 0.12954)
		(layer "B.Cu")
		(net "JTAG_TRC_PCH_PTI<4>")
	)
	(segment
		(start 385.820158 -60.704984)
		(end 386.198618 -60.704984)
		(width 0.12954)
		(layer "B.Cu")
		(net "JTAG_TRC_PCH_PTI<4>")
	)
	(segment
		(start 387.981444 -57.837324)
		(end 388.53618 -57.282588)
		(width 0.12954)
		(layer "B.Cu")
		(net "JTAG_TRC_PCH_PTI<4>")
	)
	(segment
		(start 387.095238 -60.704984)
		(end 387.473698 -60.704984)
		(width 0.12954)
		(layer "B.Cu")
		(net "JTAG_TRC_PCH_PTI<4>")
	)
	(segment
		(start 385.561078 -57.837324)
		(end 385.690618 -57.966864)
		(width 0.12954)
		(layer "B.Cu")
		(net "JTAG_TRC_PCH_PTI<4>")
	)
	(segment
		(start 387.603238 -60.575444)
		(end 387.603238 -57.966864)
		(width 0.12954)
		(layer "B.Cu")
		(net "JTAG_TRC_PCH_PTI<4>")
	)
	(segment
		(start 386.965698 -57.966864)
		(end 386.965698 -60.575444)
		(width 0.12954)
		(layer "B.Cu")
		(net "JTAG_TRC_PCH_PTI<4>")
	)
	(segment
		(start 386.198618 -60.704984)
		(end 386.328158 -60.575444)
		(width 0.12954)
		(layer "B.Cu")
		(net "JTAG_TRC_PCH_PTI<4>")
	)
	(segment
		(start 382.027176 -57.837324)
		(end 385.561078 -57.837324)
		(width 0.12954)
		(layer "B.Cu")
		(net "JTAG_TRC_PCH_PTI<4>")
	)
	(segment
		(start 385.690618 -60.575444)
		(end 385.820158 -60.704984)
		(width 0.12954)
		(layer "B.Cu")
		(net "JTAG_TRC_PCH_PTI<4>")
	)
	(segment
		(start 387.732778 -57.837324)
		(end 387.981444 -57.837324)
		(width 0.12954)
		(layer "B.Cu")
		(net "JTAG_TRC_PCH_PTI<4>")
	)
	(segment
		(start 387.603238 -57.966864)
		(end 387.732778 -57.837324)
		(width 0.12954)
		(layer "B.Cu")
		(net "JTAG_TRC_PCH_PTI<4>")
	)
	(segment
		(start 386.457698 -57.837324)
		(end 386.836158 -57.837324)
		(width 0.12954)
		(layer "B.Cu")
		(net "JTAG_TRC_PCH_PTI<4>")
	)
	(segment
		(start 386.965698 -60.575444)
		(end 387.095238 -60.704984)
		(width 0.12954)
		(layer "B.Cu")
		(net "JTAG_TRC_PCH_PTI<4>")
	)
	(segment
		(start 386.328158 -57.966864)
		(end 386.457698 -57.837324)
		(width 0.12954)
		(layer "B.Cu")
		(net "JTAG_TRC_PCH_PTI<4>")
	)
	(segment
		(start 386.328158 -60.575444)
		(end 386.328158 -57.966864)
		(width 0.12954)
		(layer "B.Cu")
		(net "JTAG_TRC_PCH_PTI<4>")
	)
	(segment
		(start 340.789006 -38.089332)
		(end 340.789006 -38.014402)
		(width 0.0889)
		(layer "F.Cu")
		(net "JTAG_TRC_PCH_PTI<3>")
	)
	(segment
		(start 385.37896 -56.756808)
		(end 385.37896 -56.595772)
		(width 0.12954)
		(layer "F.Cu")
		(net "JTAG_TRC_PCH_PTI<3>")
	)
	(segment
		(start 379.97257 -53.636926)
		(end 379.687328 -53.922168)
		(width 0.12954)
		(layer "F.Cu")
		(net "JTAG_TRC_PCH_PTI<3>")
	)
	(segment
		(start 379.705108 -53.186076)
		(end 379.97257 -53.453538)
		(width 0.12954)
		(layer "F.Cu")
		(net "JTAG_TRC_PCH_PTI<3>")
	)
	(segment
		(start 378.158502 -49.07026)
		(end 378.158502 -49.44872)
		(width 0.12954)
		(layer "F.Cu")
		(net "JTAG_TRC_PCH_PTI<3>")
	)
	(segment
		(start 377.2535 -45.601128)
		(end 377.2535 -46.26102)
		(width 0.12954)
		(layer "F.Cu")
		(net "JTAG_TRC_PCH_PTI<3>")
	)
	(segment
		(start 386.0165 -56.756808)
		(end 386.14604 -56.886348)
		(width 0.12954)
		(layer "F.Cu")
		(net "JTAG_TRC_PCH_PTI<3>")
	)
	(segment
		(start 340.901782 -38.202108)
		(end 340.789006 -38.089332)
		(width 0.0889)
		(layer "F.Cu")
		(net "JTAG_TRC_PCH_PTI<3>")
	)
	(segment
		(start 379.07087 -52.735226)
		(end 378.785628 -53.020468)
		(width 0.12954)
		(layer "F.Cu")
		(net "JTAG_TRC_PCH_PTI<3>")
	)
	(segment
		(start 340.607396 -37.741606)
		(end 340.607396 -37.54628)
		(width 0.0889)
		(layer "F.Cu")
		(net "JTAG_TRC_PCH_PTI<3>")
	)
	(segment
		(start 378.62002 -52.284376)
		(end 378.803408 -52.284376)
		(width 0.12954)
		(layer "F.Cu")
		(net "JTAG_TRC_PCH_PTI<3>")
	)
	(segment
		(start 378.028962 -46.39056)
		(end 378.158502 -46.5201)
		(width 0.12954)
		(layer "F.Cu")
		(net "JTAG_TRC_PCH_PTI<3>")
	)
	(segment
		(start 377.38304 -39.038022)
		(end 377.2535 -39.167562)
		(width 0.12954)
		(layer "F.Cu")
		(net "JTAG_TRC_PCH_PTI<3>")
	)
	(segment
		(start 382.009142 -56.42737)
		(end 384.423158 -56.42737)
		(width 0.12954)
		(layer "F.Cu")
		(net "JTAG_TRC_PCH_PTI<3>")
	)
	(segment
		(start 379.97257 -53.453538)
		(end 379.97257 -53.636926)
		(width 0.12954)
		(layer "F.Cu")
		(net "JTAG_TRC_PCH_PTI<3>")
	)
	(segment
		(start 344.241882 -26.773632)
		(end 344.241882 -19.405346)
		(width 0.12954)
		(layer "F.Cu")
		(net "JTAG_TRC_PCH_PTI<3>")
	)
	(segment
		(start 378.158502 -41.504108)
		(end 378.158502 -41.882568)
		(width 0.12954)
		(layer "F.Cu")
		(net "JTAG_TRC_PCH_PTI<3>")
	)
	(segment
		(start 340.661752 -34.57702)
		(end 342.520016 -32.718756)
		(width 0.0889)
		(layer "F.Cu")
		(net "JTAG_TRC_PCH_PTI<3>")
	)
	(segment
		(start 378.028962 -48.94072)
		(end 378.158502 -49.07026)
		(width 0.12954)
		(layer "F.Cu")
		(net "JTAG_TRC_PCH_PTI<3>")
	)
	(segment
		(start 377.38304 -50.2158)
		(end 378.028962 -50.2158)
		(width 0.12954)
		(layer "F.Cu")
		(net "JTAG_TRC_PCH_PTI<3>")
	)
	(segment
		(start 377.55068 -42.520108)
		(end 377.68022 -42.649648)
		(width 0.12954)
		(layer "F.Cu")
		(net "JTAG_TRC_PCH_PTI<3>")
	)
	(segment
		(start 377.55068 -36.723574)
		(end 377.55068 -37.633402)
		(width 0.12954)
		(layer "F.Cu")
		(net "JTAG_TRC_PCH_PTI<3>")
	)
	(segment
		(start 377.38304 -48.30318)
		(end 377.2535 -48.43272)
		(width 0.12954)
		(layer "F.Cu")
		(net "JTAG_TRC_PCH_PTI<3>")
	)
	(segment
		(start 378.028962 -43.287188)
		(end 377.68022 -43.287188)
		(width 0.12954)
		(layer "F.Cu")
		(net "JTAG_TRC_PCH_PTI<3>")
	)
	(segment
		(start 378.158502 -48.17364)
		(end 378.028962 -48.30318)
		(width 0.12954)
		(layer "F.Cu")
		(net "JTAG_TRC_PCH_PTI<3>")
	)
	(segment
		(start 377.55068 -43.795188)
		(end 377.68022 -43.924728)
		(width 0.12954)
		(layer "F.Cu")
		(net "JTAG_TRC_PCH_PTI<3>")
	)
	(segment
		(start 377.68022 -44.562268)
		(end 377.55068 -44.691808)
		(width 0.12954)
		(layer "F.Cu")
		(net "JTAG_TRC_PCH_PTI<3>")
	)
	(segment
		(start 377.2535 -38.270942)
		(end 377.38304 -38.400482)
		(width 0.12954)
		(layer "F.Cu")
		(net "JTAG_TRC_PCH_PTI<3>")
	)
	(segment
		(start 378.15139 -52.569618)
		(end 378.334778 -52.569618)
		(width 0.12954)
		(layer "F.Cu")
		(net "JTAG_TRC_PCH_PTI<3>")
	)
	(segment
		(start 378.028962 -48.30318)
		(end 377.38304 -48.30318)
		(width 0.12954)
		(layer "F.Cu")
		(net "JTAG_TRC_PCH_PTI<3>")
	)
	(segment
		(start 378.028962 -43.924728)
		(end 378.158502 -44.054268)
		(width 0.12954)
		(layer "F.Cu")
		(net "JTAG_TRC_PCH_PTI<3>")
	)
	(segment
		(start 385.24942 -56.886348)
		(end 385.37896 -56.756808)
		(width 0.12954)
		(layer "F.Cu")
		(net "JTAG_TRC_PCH_PTI<3>")
	)
	(segment
		(start 379.236478 -53.471318)
		(end 379.52172 -53.186076)
		(width 0.12954)
		(layer "F.Cu")
		(net "JTAG_TRC_PCH_PTI<3>")
	)
	(segment
		(start 377.2535 -50.98288)
		(end 377.2535 -51.671728)
		(width 0.12954)
		(layer "F.Cu")
		(net "JTAG_TRC_PCH_PTI<3>")
	)
	(segment
		(start 377.38304 -39.675562)
		(end 377.42114 -39.675562)
		(width 0.12954)
		(layer "F.Cu")
		(net "JTAG_TRC_PCH_PTI<3>")
	)
	(segment
		(start 384.882136 -56.886348)
		(end 385.24942 -56.886348)
		(width 0.12954)
		(layer "F.Cu")
		(net "JTAG_TRC_PCH_PTI<3>")
	)
	(segment
		(start 377.38304 -46.39056)
		(end 378.028962 -46.39056)
		(width 0.12954)
		(layer "F.Cu")
		(net "JTAG_TRC_PCH_PTI<3>")
	)
	(segment
		(start 377.2535 -50.08626)
		(end 377.38304 -50.2158)
		(width 0.12954)
		(layer "F.Cu")
		(net "JTAG_TRC_PCH_PTI<3>")
	)
	(segment
		(start 378.028962 -42.012108)
		(end 377.68022 -42.012108)
		(width 0.12954)
		(layer "F.Cu")
		(net "JTAG_TRC_PCH_PTI<3>")
	)
	(segment
		(start 379.687328 -53.922168)
		(end 379.687328 -54.105556)
		(width 0.12954)
		(layer "F.Cu")
		(net "JTAG_TRC_PCH_PTI<3>")
	)
	(segment
		(start 386.14604 -56.886348)
		(end 387.35 -56.886348)
		(width 0.12954)
		(layer "F.Cu")
		(net "JTAG_TRC_PCH_PTI<3>")
	)
	(segment
		(start 378.158502 -49.44872)
		(end 378.028962 -49.57826)
		(width 0.12954)
		(layer "F.Cu")
		(net "JTAG_TRC_PCH_PTI<3>")
	)
	(segment
		(start 386.0165 -56.595772)
		(end 386.0165 -56.756808)
		(width 0.12954)
		(layer "F.Cu")
		(net "JTAG_TRC_PCH_PTI<3>")
	)
	(segment
		(start 377.55068 -37.633402)
		(end 377.42114 -37.762942)
		(width 0.12954)
		(layer "F.Cu")
		(net "JTAG_TRC_PCH_PTI<3>")
	)
	(segment
		(start 377.68022 -43.287188)
		(end 377.55068 -43.416728)
		(width 0.12954)
		(layer "F.Cu")
		(net "JTAG_TRC_PCH_PTI<3>")
	)
	(segment
		(start 378.158502 -46.89856)
		(end 378.028962 -47.0281)
		(width 0.12954)
		(layer "F.Cu")
		(net "JTAG_TRC_PCH_PTI<3>")
	)
	(segment
		(start 378.028962 -50.2158)
		(end 378.158502 -50.34534)
		(width 0.12954)
		(layer "F.Cu")
		(net "JTAG_TRC_PCH_PTI<3>")
	)
	(segment
		(start 378.803408 -52.284376)
		(end 379.07087 -52.551838)
		(width 0.12954)
		(layer "F.Cu")
		(net "JTAG_TRC_PCH_PTI<3>")
	)
	(segment
		(start 377.42114 -37.762942)
		(end 377.38304 -37.762942)
		(width 0.12954)
		(layer "F.Cu")
		(net "JTAG_TRC_PCH_PTI<3>")
	)
	(segment
		(start 346.68587 -16.961358)
		(end 357.788464 -16.961358)
		(width 0.12954)
		(layer "F.Cu")
		(net "JTAG_TRC_PCH_PTI<3>")
	)
	(segment
		(start 377.38304 -48.94072)
		(end 378.028962 -48.94072)
		(width 0.12954)
		(layer "F.Cu")
		(net "JTAG_TRC_PCH_PTI<3>")
	)
	(segment
		(start 377.2535 -47.5361)
		(end 377.38304 -47.66564)
		(width 0.12954)
		(layer "F.Cu")
		(net "JTAG_TRC_PCH_PTI<3>")
	)
	(segment
		(start 377.2535 -51.671728)
		(end 378.15139 -52.569618)
		(width 0.12954)
		(layer "F.Cu")
		(net "JTAG_TRC_PCH_PTI<3>")
	)
	(segment
		(start 377.2535 -48.81118)
		(end 377.38304 -48.94072)
		(width 0.12954)
		(layer "F.Cu")
		(net "JTAG_TRC_PCH_PTI<3>")
	)
	(segment
		(start 378.028962 -50.85334)
		(end 377.38304 -50.85334)
		(width 0.12954)
		(layer "F.Cu")
		(net "JTAG_TRC_PCH_PTI<3>")
	)
	(segment
		(start 378.158502 -43.157648)
		(end 378.028962 -43.287188)
		(width 0.12954)
		(layer "F.Cu")
		(net "JTAG_TRC_PCH_PTI<3>")
	)
	(segment
		(start 384.423158 -56.42737)
		(end 384.882136 -56.886348)
		(width 0.12954)
		(layer "F.Cu")
		(net "JTAG_TRC_PCH_PTI<3>")
	)
	(segment
		(start 387.35 -56.886348)
		(end 387.642608 -57.178956)
		(width 0.12954)
		(layer "F.Cu")
		(net "JTAG_TRC_PCH_PTI<3>")
	)
	(segment
		(start 377.2535 -46.26102)
		(end 377.38304 -46.39056)
		(width 0.12954)
		(layer "F.Cu")
		(net "JTAG_TRC_PCH_PTI<3>")
	)
	(segment
		(start 377.38304 -49.57826)
		(end 377.2535 -49.7078)
		(width 0.12954)
		(layer "F.Cu")
		(net "JTAG_TRC_PCH_PTI<3>")
	)
	(segment
		(start 377.68022 -42.649648)
		(end 378.028962 -42.649648)
		(width 0.12954)
		(layer "F.Cu")
		(net "JTAG_TRC_PCH_PTI<3>")
	)
	(segment
		(start 357.788464 -16.961358)
		(end 377.55068 -36.723574)
		(width 0.12954)
		(layer "F.Cu")
		(net "JTAG_TRC_PCH_PTI<3>")
	)
	(segment
		(start 342.520016 -32.718756)
		(end 342.520016 -32.426148)
		(width 0.0889)
		(layer "F.Cu")
		(net "JTAG_TRC_PCH_PTI<3>")
	)
	(segment
		(start 378.158502 -47.79518)
		(end 378.158502 -48.17364)
		(width 0.12954)
		(layer "F.Cu")
		(net "JTAG_TRC_PCH_PTI<3>")
	)
	(segment
		(start 377.38304 -47.66564)
		(end 378.028962 -47.66564)
		(width 0.12954)
		(layer "F.Cu")
		(net "JTAG_TRC_PCH_PTI<3>")
	)
	(segment
		(start 340.901782 -38.465252)
		(end 340.901782 -38.202108)
		(width 0.0889)
		(layer "F.Cu")
		(net "JTAG_TRC_PCH_PTI<3>")
	)
	(segment
		(start 377.55068 -43.416728)
		(end 377.55068 -43.795188)
		(width 0.12954)
		(layer "F.Cu")
		(net "JTAG_TRC_PCH_PTI<3>")
	)
	(segment
		(start 379.07087 -52.551838)
		(end 379.07087 -52.735226)
		(width 0.12954)
		(layer "F.Cu")
		(net "JTAG_TRC_PCH_PTI<3>")
	)
	(segment
		(start 377.2535 -39.167562)
		(end 377.2535 -39.546022)
		(width 0.12954)
		(layer "F.Cu")
		(net "JTAG_TRC_PCH_PTI<3>")
	)
	(segment
		(start 342.520016 -32.426148)
		(end 342.630506 -32.315658)
		(width 0.0889)
		(layer "F.Cu")
		(net "JTAG_TRC_PCH_PTI<3>")
	)
	(segment
		(start 379.52172 -53.186076)
		(end 379.705108 -53.186076)
		(width 0.12954)
		(layer "F.Cu")
		(net "JTAG_TRC_PCH_PTI<3>")
	)
	(segment
		(start 378.158502 -41.882568)
		(end 378.028962 -42.012108)
		(width 0.12954)
		(layer "F.Cu")
		(net "JTAG_TRC_PCH_PTI<3>")
	)
	(segment
		(start 378.158502 -50.34534)
		(end 378.158502 -50.7238)
		(width 0.12954)
		(layer "F.Cu")
		(net "JTAG_TRC_PCH_PTI<3>")
	)
	(segment
		(start 377.55068 -44.691808)
		(end 377.55068 -45.303948)
		(width 0.12954)
		(layer "F.Cu")
		(net "JTAG_TRC_PCH_PTI<3>")
	)
	(segment
		(start 344.058748 -28.583128)
		(end 344.058748 -27.215846)
		(width 0.12954)
		(layer "F.Cu")
		(net "JTAG_TRC_PCH_PTI<3>")
	)
	(segment
		(start 377.55068 -39.805102)
		(end 377.55068 -41.245028)
		(width 0.12954)
		(layer "F.Cu")
		(net "JTAG_TRC_PCH_PTI<3>")
	)
	(segment
		(start 377.38304 -38.400482)
		(end 377.42114 -38.400482)
		(width 0.12954)
		(layer "F.Cu")
		(net "JTAG_TRC_PCH_PTI<3>")
	)
	(segment
		(start 377.55068 -41.245028)
		(end 377.68022 -41.374568)
		(width 0.12954)
		(layer "F.Cu")
		(net "JTAG_TRC_PCH_PTI<3>")
	)
	(segment
		(start 378.028962 -47.0281)
		(end 377.38304 -47.0281)
		(width 0.12954)
		(layer "F.Cu")
		(net "JTAG_TRC_PCH_PTI<3>")
	)
	(segment
		(start 377.2535 -39.546022)
		(end 377.38304 -39.675562)
		(width 0.12954)
		(layer "F.Cu")
		(net "JTAG_TRC_PCH_PTI<3>")
	)
	(segment
		(start 378.158502 -50.7238)
		(end 378.028962 -50.85334)
		(width 0.12954)
		(layer "F.Cu")
		(net "JTAG_TRC_PCH_PTI<3>")
	)
	(segment
		(start 377.55068 -38.530022)
		(end 377.55068 -38.908482)
		(width 0.12954)
		(layer "F.Cu")
		(net "JTAG_TRC_PCH_PTI<3>")
	)
	(segment
		(start 378.785628 -53.020468)
		(end 378.785628 -53.203856)
		(width 0.12954)
		(layer "F.Cu")
		(net "JTAG_TRC_PCH_PTI<3>")
	)
	(segment
		(start 377.55068 -42.141648)
		(end 377.55068 -42.520108)
		(width 0.12954)
		(layer "F.Cu")
		(net "JTAG_TRC_PCH_PTI<3>")
	)
	(segment
		(start 340.661752 -37.361622)
		(end 340.661752 -34.57702)
		(width 0.0889)
		(layer "F.Cu")
		(net "JTAG_TRC_PCH_PTI<3>")
	)
	(segment
		(start 378.334778 -52.569618)
		(end 378.62002 -52.284376)
		(width 0.12954)
		(layer "F.Cu")
		(net "JTAG_TRC_PCH_PTI<3>")
	)
	(segment
		(start 378.158502 -44.054268)
		(end 378.158502 -44.432728)
		(width 0.12954)
		(layer "F.Cu")
		(net "JTAG_TRC_PCH_PTI<3>")
	)
	(segment
		(start 343.557098 -31.389066)
		(end 343.557098 -29.084778)
		(width 0.12954)
		(layer "F.Cu")
		(net "JTAG_TRC_PCH_PTI<3>")
	)
	(segment
		(start 377.2535 -48.43272)
		(end 377.2535 -48.81118)
		(width 0.12954)
		(layer "F.Cu")
		(net "JTAG_TRC_PCH_PTI<3>")
	)
	(segment
		(start 377.2535 -47.15764)
		(end 377.2535 -47.5361)
		(width 0.12954)
		(layer "F.Cu")
		(net "JTAG_TRC_PCH_PTI<3>")
	)
	(segment
		(start 377.42114 -39.038022)
		(end 377.38304 -39.038022)
		(width 0.12954)
		(layer "F.Cu")
		(net "JTAG_TRC_PCH_PTI<3>")
	)
	(segment
		(start 340.789006 -38.014402)
		(end 340.607396 -37.741606)
		(width 0.0889)
		(layer "F.Cu")
		(net "JTAG_TRC_PCH_PTI<3>")
	)
	(segment
		(start 377.68022 -42.012108)
		(end 377.55068 -42.141648)
		(width 0.12954)
		(layer "F.Cu")
		(net "JTAG_TRC_PCH_PTI<3>")
	)
	(segment
		(start 377.2535 -49.7078)
		(end 377.2535 -50.08626)
		(width 0.12954)
		(layer "F.Cu")
		(net "JTAG_TRC_PCH_PTI<3>")
	)
	(segment
		(start 378.785628 -53.203856)
		(end 379.05309 -53.471318)
		(width 0.12954)
		(layer "F.Cu")
		(net "JTAG_TRC_PCH_PTI<3>")
	)
	(segment
		(start 377.55068 -45.303948)
		(end 377.2535 -45.601128)
		(width 0.12954)
		(layer "F.Cu")
		(net "JTAG_TRC_PCH_PTI<3>")
	)
	(segment
		(start 377.38304 -47.0281)
		(end 377.2535 -47.15764)
		(width 0.12954)
		(layer "F.Cu")
		(net "JTAG_TRC_PCH_PTI<3>")
	)
	(segment
		(start 377.42114 -38.400482)
		(end 377.55068 -38.530022)
		(width 0.12954)
		(layer "F.Cu")
		(net "JTAG_TRC_PCH_PTI<3>")
	)
	(segment
		(start 377.38304 -37.762942)
		(end 377.2535 -37.892482)
		(width 0.12954)
		(layer "F.Cu")
		(net "JTAG_TRC_PCH_PTI<3>")
	)
	(segment
		(start 344.241882 -19.405346)
		(end 346.68587 -16.961358)
		(width 0.12954)
		(layer "F.Cu")
		(net "JTAG_TRC_PCH_PTI<3>")
	)
	(segment
		(start 378.028962 -47.66564)
		(end 378.158502 -47.79518)
		(width 0.12954)
		(layer "F.Cu")
		(net "JTAG_TRC_PCH_PTI<3>")
	)
	(segment
		(start 379.687328 -54.105556)
		(end 382.009142 -56.42737)
		(width 0.12954)
		(layer "F.Cu")
		(net "JTAG_TRC_PCH_PTI<3>")
	)
	(segment
		(start 340.607396 -37.54628)
		(end 340.661752 -37.361622)
		(width 0.0889)
		(layer "F.Cu")
		(net "JTAG_TRC_PCH_PTI<3>")
	)
	(segment
		(start 385.5085 -56.466232)
		(end 385.88696 -56.466232)
		(width 0.12954)
		(layer "F.Cu")
		(net "JTAG_TRC_PCH_PTI<3>")
	)
	(segment
		(start 342.630506 -32.315658)
		(end 343.557098 -31.389066)
		(width 0.12954)
		(layer "F.Cu")
		(net "JTAG_TRC_PCH_PTI<3>")
	)
	(segment
		(start 344.058748 -27.215846)
		(end 344.241882 -26.773632)
		(width 0.12954)
		(layer "F.Cu")
		(net "JTAG_TRC_PCH_PTI<3>")
	)
	(segment
		(start 378.028962 -49.57826)
		(end 377.38304 -49.57826)
		(width 0.12954)
		(layer "F.Cu")
		(net "JTAG_TRC_PCH_PTI<3>")
	)
	(segment
		(start 387.642608 -57.178956)
		(end 388.713472 -58.24982)
		(width 0.12954)
		(layer "F.Cu")
		(net "JTAG_TRC_PCH_PTI<3>")
	)
	(segment
		(start 377.55068 -38.908482)
		(end 377.42114 -39.038022)
		(width 0.12954)
		(layer "F.Cu")
		(net "JTAG_TRC_PCH_PTI<3>")
	)
	(segment
		(start 385.37896 -56.595772)
		(end 385.5085 -56.466232)
		(width 0.12954)
		(layer "F.Cu")
		(net "JTAG_TRC_PCH_PTI<3>")
	)
	(segment
		(start 378.028962 -44.562268)
		(end 377.68022 -44.562268)
		(width 0.12954)
		(layer "F.Cu")
		(net "JTAG_TRC_PCH_PTI<3>")
	)
	(segment
		(start 378.158502 -44.432728)
		(end 378.028962 -44.562268)
		(width 0.12954)
		(layer "F.Cu")
		(net "JTAG_TRC_PCH_PTI<3>")
	)
	(segment
		(start 377.68022 -41.374568)
		(end 378.028962 -41.374568)
		(width 0.12954)
		(layer "F.Cu")
		(net "JTAG_TRC_PCH_PTI<3>")
	)
	(segment
		(start 378.158502 -42.779188)
		(end 378.158502 -43.157648)
		(width 0.12954)
		(layer "F.Cu")
		(net "JTAG_TRC_PCH_PTI<3>")
	)
	(segment
		(start 343.557098 -29.084778)
		(end 344.058748 -28.583128)
		(width 0.12954)
		(layer "F.Cu")
		(net "JTAG_TRC_PCH_PTI<3>")
	)
	(segment
		(start 379.05309 -53.471318)
		(end 379.236478 -53.471318)
		(width 0.12954)
		(layer "F.Cu")
		(net "JTAG_TRC_PCH_PTI<3>")
	)
	(segment
		(start 388.713472 -58.24982)
		(end 392.034776 -58.24982)
		(width 0.12954)
		(layer "F.Cu")
		(net "JTAG_TRC_PCH_PTI<3>")
	)
	(segment
		(start 378.028962 -41.374568)
		(end 378.158502 -41.504108)
		(width 0.12954)
		(layer "F.Cu")
		(net "JTAG_TRC_PCH_PTI<3>")
	)
	(segment
		(start 385.88696 -56.466232)
		(end 386.0165 -56.595772)
		(width 0.12954)
		(layer "F.Cu")
		(net "JTAG_TRC_PCH_PTI<3>")
	)
	(segment
		(start 377.38304 -50.85334)
		(end 377.2535 -50.98288)
		(width 0.12954)
		(layer "F.Cu")
		(net "JTAG_TRC_PCH_PTI<3>")
	)
	(segment
		(start 378.028962 -42.649648)
		(end 378.158502 -42.779188)
		(width 0.12954)
		(layer "F.Cu")
		(net "JTAG_TRC_PCH_PTI<3>")
	)
	(segment
		(start 377.2535 -37.892482)
		(end 377.2535 -38.270942)
		(width 0.12954)
		(layer "F.Cu")
		(net "JTAG_TRC_PCH_PTI<3>")
	)
	(segment
		(start 378.158502 -46.5201)
		(end 378.158502 -46.89856)
		(width 0.12954)
		(layer "F.Cu")
		(net "JTAG_TRC_PCH_PTI<3>")
	)
	(segment
		(start 377.42114 -39.675562)
		(end 377.55068 -39.805102)
		(width 0.12954)
		(layer "F.Cu")
		(net "JTAG_TRC_PCH_PTI<3>")
	)
	(segment
		(start 377.68022 -43.924728)
		(end 378.028962 -43.924728)
		(width 0.12954)
		(layer "F.Cu")
		(net "JTAG_TRC_PCH_PTI<3>")
	)
	(via
		(at 387.642608 -57.178956)
		(size 0.508)
		(drill 0.254)
		(layers "F.Cu" "B.Cu")
		(net "JTAG_TRC_PCH_PTI<3>")
	)
	(segment
		(start 379.766322 -55.466742)
		(end 380.061978 -55.171086)
		(width 0.12954)
		(layer "F.Cu")
		(net "JTAG_TRC_PCH_PTI<2>")
	)
	(segment
		(start 356.824788 -17.319498)
		(end 356.446328 -17.319498)
		(width 0.12954)
		(layer "F.Cu")
		(net "JTAG_TRC_PCH_PTI<2>")
	)
	(segment
		(start 349.433388 -18.008854)
		(end 349.303848 -17.879314)
		(width 0.12954)
		(layer "F.Cu")
		(net "JTAG_TRC_PCH_PTI<2>")
	)
	(segment
		(start 352.999548 -17.319498)
		(end 352.621088 -17.319498)
		(width 0.12954)
		(layer "F.Cu")
		(net "JTAG_TRC_PCH_PTI<2>")
	)
	(segment
		(start 378.892816 -53.818536)
		(end 378.709428 -53.818536)
		(width 0.12954)
		(layer "F.Cu")
		(net "JTAG_TRC_PCH_PTI<2>")
	)
	(segment
		(start 377.19254 -44.257722)
		(end 377.063 -44.128182)
		(width 0.12954)
		(layer "F.Cu")
		(net "JTAG_TRC_PCH_PTI<2>")
	)
	(segment
		(start 378.413772 -54.114192)
		(end 378.230384 -54.114192)
		(width 0.12954)
		(layer "F.Cu")
		(net "JTAG_TRC_PCH_PTI<2>")
	)
	(segment
		(start 377.19254 -42.982642)
		(end 377.063 -42.853102)
		(width 0.12954)
		(layer "F.Cu")
		(net "JTAG_TRC_PCH_PTI<2>")
	)
	(segment
		(start 355.549708 -17.319498)
		(end 355.171248 -17.319498)
		(width 0.12954)
		(layer "F.Cu")
		(net "JTAG_TRC_PCH_PTI<2>")
	)
	(segment
		(start 377.0249 -42.215562)
		(end 377.063 -42.215562)
		(width 0.12954)
		(layer "F.Cu")
		(net "JTAG_TRC_PCH_PTI<2>")
	)
	(segment
		(start 356.187248 -18.008854)
		(end 355.808788 -18.008854)
		(width 0.12954)
		(layer "F.Cu")
		(net "JTAG_TRC_PCH_PTI<2>")
	)
	(segment
		(start 355.679248 -17.879314)
		(end 355.679248 -17.449038)
		(width 0.12954)
		(layer "F.Cu")
		(net "JTAG_TRC_PCH_PTI<2>")
	)
	(segment
		(start 341.211154 -37.55517)
		(end 341.200994 -37.765482)
		(width 0.0889)
		(layer "F.Cu")
		(net "JTAG_TRC_PCH_PTI<2>")
	)
	(segment
		(start 378.230384 -54.114192)
		(end 377.962922 -53.84673)
		(width 0.12954)
		(layer "F.Cu")
		(net "JTAG_TRC_PCH_PTI<2>")
	)
	(segment
		(start 353.896168 -17.319498)
		(end 353.766628 -17.449038)
		(width 0.12954)
		(layer "F.Cu")
		(net "JTAG_TRC_PCH_PTI<2>")
	)
	(segment
		(start 377.063 -43.490642)
		(end 377.19254 -43.361102)
		(width 0.12954)
		(layer "F.Cu")
		(net "JTAG_TRC_PCH_PTI<2>")
	)
	(segment
		(start 351.346008 -17.319498)
		(end 351.216468 -17.449038)
		(width 0.12954)
		(layer "F.Cu")
		(net "JTAG_TRC_PCH_PTI<2>")
	)
	(segment
		(start 354.274628 -17.319498)
		(end 353.896168 -17.319498)
		(width 0.12954)
		(layer "F.Cu")
		(net "JTAG_TRC_PCH_PTI<2>")
	)
	(segment
		(start 351.216468 -17.449038)
		(end 351.216468 -17.879314)
		(width 0.12954)
		(layer "F.Cu")
		(net "JTAG_TRC_PCH_PTI<2>")
	)
	(segment
		(start 377.063 -44.765722)
		(end 377.19254 -44.636182)
		(width 0.12954)
		(layer "F.Cu")
		(net "JTAG_TRC_PCH_PTI<2>")
	)
	(segment
		(start 378.709428 -53.818536)
		(end 378.413772 -54.114192)
		(width 0.12954)
		(layer "F.Cu")
		(net "JTAG_TRC_PCH_PTI<2>")
	)
	(segment
		(start 355.041708 -17.449038)
		(end 355.041708 -17.879314)
		(width 0.12954)
		(layer "F.Cu")
		(net "JTAG_TRC_PCH_PTI<2>")
	)
	(segment
		(start 392.034776 -58.749946)
		(end 388.451598 -58.749946)
		(width 0.12954)
		(layer "F.Cu")
		(net "JTAG_TRC_PCH_PTI<2>")
	)
	(segment
		(start 349.303848 -17.879314)
		(end 349.303848 -17.449038)
		(width 0.12954)
		(layer "F.Cu")
		(net "JTAG_TRC_PCH_PTI<2>")
	)
	(segment
		(start 341.10041 -38.196012)
		(end 341.401908 -38.545008)
		(width 0.0889)
		(layer "F.Cu")
		(net "JTAG_TRC_PCH_PTI<2>")
	)
	(segment
		(start 383.544318 -57.281064)
		(end 383.036064 -57.281064)
		(width 0.12954)
		(layer "F.Cu")
		(net "JTAG_TRC_PCH_PTI<2>")
	)
	(segment
		(start 377.063 -42.853102)
		(end 377.0249 -42.853102)
		(width 0.12954)
		(layer "F.Cu")
		(net "JTAG_TRC_PCH_PTI<2>")
	)
	(segment
		(start 351.216468 -17.879314)
		(end 351.086928 -18.008854)
		(width 0.12954)
		(layer "F.Cu")
		(net "JTAG_TRC_PCH_PTI<2>")
	)
	(segment
		(start 348.666308 -17.879314)
		(end 348.536768 -18.008854)
		(width 0.12954)
		(layer "F.Cu")
		(net "JTAG_TRC_PCH_PTI<2>")
	)
	(segment
		(start 351.854008 -17.449038)
		(end 351.724468 -17.319498)
		(width 0.12954)
		(layer "F.Cu")
		(net "JTAG_TRC_PCH_PTI<2>")
	)
	(segment
		(start 376.89536 -36.574984)
		(end 358.32923 -18.008854)
		(width 0.12954)
		(layer "F.Cu")
		(net "JTAG_TRC_PCH_PTI<2>")
	)
	(segment
		(start 341.147908 -37.2364)
		(end 341.211154 -37.55517)
		(width 0.0889)
		(layer "F.Cu")
		(net "JTAG_TRC_PCH_PTI<2>")
	)
	(segment
		(start 377.19254 -44.636182)
		(end 377.19254 -44.257722)
		(width 0.12954)
		(layer "F.Cu")
		(net "JTAG_TRC_PCH_PTI<2>")
	)
	(segment
		(start 353.129088 -17.449038)
		(end 352.999548 -17.319498)
		(width 0.12954)
		(layer "F.Cu")
		(net "JTAG_TRC_PCH_PTI<2>")
	)
	(segment
		(start 343.915238 -29.233368)
		(end 343.915238 -31.747206)
		(width 0.12954)
		(layer "F.Cu")
		(net "JTAG_TRC_PCH_PTI<2>")
	)
	(segment
		(start 352.362008 -18.008854)
		(end 351.983548 -18.008854)
		(width 0.12954)
		(layer "F.Cu")
		(net "JTAG_TRC_PCH_PTI<2>")
	)
	(segment
		(start 349.811848 -18.008854)
		(end 349.433388 -18.008854)
		(width 0.12954)
		(layer "F.Cu")
		(net "JTAG_TRC_PCH_PTI<2>")
	)
	(segment
		(start 377.962922 -53.84673)
		(end 377.962922 -53.663342)
		(width 0.12954)
		(layer "F.Cu")
		(net "JTAG_TRC_PCH_PTI<2>")
	)
	(segment
		(start 377.063 -40.302942)
		(end 377.0249 -40.302942)
		(width 0.12954)
		(layer "F.Cu")
		(net "JTAG_TRC_PCH_PTI<2>")
	)
	(segment
		(start 377.512072 -53.212492)
		(end 377.328684 -53.212492)
		(width 0.12954)
		(layer "F.Cu")
		(net "JTAG_TRC_PCH_PTI<2>")
	)
	(segment
		(start 348.028768 -17.449038)
		(end 347.899228 -17.319498)
		(width 0.12954)
		(layer "F.Cu")
		(net "JTAG_TRC_PCH_PTI<2>")
	)
	(segment
		(start 377.0249 -44.128182)
		(end 376.89536 -43.998642)
		(width 0.12954)
		(layer "F.Cu")
		(net "JTAG_TRC_PCH_PTI<2>")
	)
	(segment
		(start 379.132084 -55.015892)
		(end 378.864622 -54.74843)
		(width 0.12954)
		(layer "F.Cu")
		(net "JTAG_TRC_PCH_PTI<2>")
	)
	(segment
		(start 356.316788 -17.879314)
		(end 356.187248 -18.008854)
		(width 0.12954)
		(layer "F.Cu")
		(net "JTAG_TRC_PCH_PTI<2>")
	)
	(segment
		(start 377.063 -44.128182)
		(end 377.0249 -44.128182)
		(width 0.12954)
		(layer "F.Cu")
		(net "JTAG_TRC_PCH_PTI<2>")
	)
	(segment
		(start 376.89536 -40.173402)
		(end 376.89536 -36.574984)
		(width 0.12954)
		(layer "F.Cu")
		(net "JTAG_TRC_PCH_PTI<2>")
	)
	(segment
		(start 349.941388 -17.449038)
		(end 349.941388 -17.879314)
		(width 0.12954)
		(layer "F.Cu")
		(net "JTAG_TRC_PCH_PTI<2>")
	)
	(segment
		(start 344.416888 -27.28722)
		(end 344.416888 -28.731718)
		(width 0.12954)
		(layer "F.Cu")
		(net "JTAG_TRC_PCH_PTI<2>")
	)
	(segment
		(start 341.564976 -34.097468)
		(end 341.564976 -36.200588)
		(width 0.0889)
		(layer "F.Cu")
		(net "JTAG_TRC_PCH_PTI<2>")
	)
	(segment
		(start 377.0249 -44.765722)
		(end 377.063 -44.765722)
		(width 0.12954)
		(layer "F.Cu")
		(net "JTAG_TRC_PCH_PTI<2>")
	)
	(segment
		(start 347.899228 -17.319498)
		(end 347.520768 -17.319498)
		(width 0.12954)
		(layer "F.Cu")
		(net "JTAG_TRC_PCH_PTI<2>")
	)
	(segment
		(start 377.0249 -40.940482)
		(end 377.063 -40.940482)
		(width 0.12954)
		(layer "F.Cu")
		(net "JTAG_TRC_PCH_PTI<2>")
	)
	(segment
		(start 353.766628 -17.449038)
		(end 353.766628 -17.879314)
		(width 0.12954)
		(layer "F.Cu")
		(net "JTAG_TRC_PCH_PTI<2>")
	)
	(segment
		(start 376.89536 -43.620182)
		(end 377.0249 -43.490642)
		(width 0.12954)
		(layer "F.Cu")
		(net "JTAG_TRC_PCH_PTI<2>")
	)
	(segment
		(start 376.89536 -42.723562)
		(end 376.89536 -42.345102)
		(width 0.12954)
		(layer "F.Cu")
		(net "JTAG_TRC_PCH_PTI<2>")
	)
	(segment
		(start 351.854008 -17.879314)
		(end 351.854008 -17.449038)
		(width 0.12954)
		(layer "F.Cu")
		(net "JTAG_TRC_PCH_PTI<2>")
	)
	(segment
		(start 379.160278 -54.085998)
		(end 378.892816 -53.818536)
		(width 0.12954)
		(layer "F.Cu")
		(net "JTAG_TRC_PCH_PTI<2>")
	)
	(segment
		(start 377.19254 -42.086022)
		(end 377.19254 -41.707562)
		(width 0.12954)
		(layer "F.Cu")
		(net "JTAG_TRC_PCH_PTI<2>")
	)
	(segment
		(start 377.0249 -40.302942)
		(end 376.89536 -40.173402)
		(width 0.12954)
		(layer "F.Cu")
		(net "JTAG_TRC_PCH_PTI<2>")
	)
	(segment
		(start 354.404168 -17.449038)
		(end 354.274628 -17.319498)
		(width 0.12954)
		(layer "F.Cu")
		(net "JTAG_TRC_PCH_PTI<2>")
	)
	(segment
		(start 383.036064 -57.281064)
		(end 382.561338 -56.806338)
		(width 0.12954)
		(layer "F.Cu")
		(net "JTAG_TRC_PCH_PTI<2>")
	)
	(segment
		(start 376.89536 -42.345102)
		(end 377.0249 -42.215562)
		(width 0.12954)
		(layer "F.Cu")
		(net "JTAG_TRC_PCH_PTI<2>")
	)
	(segment
		(start 356.954328 -17.449038)
		(end 356.824788 -17.319498)
		(width 0.12954)
		(layer "F.Cu")
		(net "JTAG_TRC_PCH_PTI<2>")
	)
	(segment
		(start 354.912168 -18.008854)
		(end 354.533708 -18.008854)
		(width 0.12954)
		(layer "F.Cu")
		(net "JTAG_TRC_PCH_PTI<2>")
	)
	(segment
		(start 354.533708 -18.008854)
		(end 354.404168 -17.879314)
		(width 0.12954)
		(layer "F.Cu")
		(net "JTAG_TRC_PCH_PTI<2>")
	)
	(segment
		(start 352.621088 -17.319498)
		(end 352.491548 -17.449038)
		(width 0.12954)
		(layer "F.Cu")
		(net "JTAG_TRC_PCH_PTI<2>")
	)
	(segment
		(start 350.578928 -17.879314)
		(end 350.578928 -17.449038)
		(width 0.12954)
		(layer "F.Cu")
		(net "JTAG_TRC_PCH_PTI<2>")
	)
	(segment
		(start 377.19254 -40.810942)
		(end 377.19254 -40.432482)
		(width 0.12954)
		(layer "F.Cu")
		(net "JTAG_TRC_PCH_PTI<2>")
	)
	(segment
		(start 351.086928 -18.008854)
		(end 350.708468 -18.008854)
		(width 0.12954)
		(layer "F.Cu")
		(net "JTAG_TRC_PCH_PTI<2>")
	)
	(segment
		(start 351.724468 -17.319498)
		(end 351.346008 -17.319498)
		(width 0.12954)
		(layer "F.Cu")
		(net "JTAG_TRC_PCH_PTI<2>")
	)
	(segment
		(start 379.160278 -54.269386)
		(end 379.160278 -54.085998)
		(width 0.12954)
		(layer "F.Cu")
		(net "JTAG_TRC_PCH_PTI<2>")
	)
	(segment
		(start 351.983548 -18.008854)
		(end 351.854008 -17.879314)
		(width 0.12954)
		(layer "F.Cu")
		(net "JTAG_TRC_PCH_PTI<2>")
	)
	(segment
		(start 346.341954 -18.008854)
		(end 344.600022 -19.750786)
		(width 0.12954)
		(layer "F.Cu")
		(net "JTAG_TRC_PCH_PTI<2>")
	)
	(segment
		(start 341.147908 -36.617656)
		(end 341.147908 -37.2364)
		(width 0.0889)
		(layer "F.Cu")
		(net "JTAG_TRC_PCH_PTI<2>")
	)
	(segment
		(start 386.982716 -57.281064)
		(end 383.544318 -57.281064)
		(width 0.12954)
		(layer "F.Cu")
		(net "JTAG_TRC_PCH_PTI<2>")
	)
	(segment
		(start 343.915238 -31.747206)
		(end 341.928196 -33.734248)
		(width 0.12954)
		(layer "F.Cu")
		(net "JTAG_TRC_PCH_PTI<2>")
	)
	(segment
		(start 358.32923 -18.008854)
		(end 357.083868 -18.008854)
		(width 0.12954)
		(layer "F.Cu")
		(net "JTAG_TRC_PCH_PTI<2>")
	)
	(segment
		(start 380.061978 -55.171086)
		(end 380.061978 -54.987698)
		(width 0.12954)
		(layer "F.Cu")
		(net "JTAG_TRC_PCH_PTI<2>")
	)
	(segment
		(start 377.0249 -42.853102)
		(end 376.89536 -42.723562)
		(width 0.12954)
		(layer "F.Cu")
		(net "JTAG_TRC_PCH_PTI<2>")
	)
	(segment
		(start 348.158308 -18.008854)
		(end 348.028768 -17.879314)
		(width 0.12954)
		(layer "F.Cu")
		(net "JTAG_TRC_PCH_PTI<2>")
	)
	(segment
		(start 380.061978 -54.987698)
		(end 379.794516 -54.720236)
		(width 0.12954)
		(layer "F.Cu")
		(net "JTAG_TRC_PCH_PTI<2>")
	)
	(segment
		(start 377.0249 -43.490642)
		(end 377.063 -43.490642)
		(width 0.12954)
		(layer "F.Cu")
		(net "JTAG_TRC_PCH_PTI<2>")
	)
	(segment
		(start 347.391228 -17.449038)
		(end 347.391228 -17.879314)
		(width 0.12954)
		(layer "F.Cu")
		(net "JTAG_TRC_PCH_PTI<2>")
	)
	(segment
		(start 356.954328 -17.879314)
		(end 356.954328 -17.449038)
		(width 0.12954)
		(layer "F.Cu")
		(net "JTAG_TRC_PCH_PTI<2>")
	)
	(segment
		(start 377.063 -41.578022)
		(end 377.0249 -41.578022)
		(width 0.12954)
		(layer "F.Cu")
		(net "JTAG_TRC_PCH_PTI<2>")
	)
	(segment
		(start 341.928196 -33.734248)
		(end 341.564976 -34.097468)
		(width 0.0889)
		(layer "F.Cu")
		(net "JTAG_TRC_PCH_PTI<2>")
	)
	(segment
		(start 347.391228 -17.879314)
		(end 347.261688 -18.008854)
		(width 0.12954)
		(layer "F.Cu")
		(net "JTAG_TRC_PCH_PTI<2>")
	)
	(segment
		(start 380.92253 -56.806338)
		(end 379.766322 -55.65013)
		(width 0.12954)
		(layer "F.Cu")
		(net "JTAG_TRC_PCH_PTI<2>")
	)
	(segment
		(start 377.991116 -52.916836)
		(end 377.807728 -52.916836)
		(width 0.12954)
		(layer "F.Cu")
		(net "JTAG_TRC_PCH_PTI<2>")
	)
	(segment
		(start 347.520768 -17.319498)
		(end 347.391228 -17.449038)
		(width 0.12954)
		(layer "F.Cu")
		(net "JTAG_TRC_PCH_PTI<2>")
	)
	(segment
		(start 377.328684 -53.212492)
		(end 376.89536 -52.779168)
		(width 0.12954)
		(layer "F.Cu")
		(net "JTAG_TRC_PCH_PTI<2>")
	)
	(segment
		(start 349.941388 -17.879314)
		(end 349.811848 -18.008854)
		(width 0.12954)
		(layer "F.Cu")
		(net "JTAG_TRC_PCH_PTI<2>")
	)
	(segment
		(start 378.258578 -53.367686)
		(end 378.258578 -53.184298)
		(width 0.12954)
		(layer "F.Cu")
		(net "JTAG_TRC_PCH_PTI<2>")
	)
	(segment
		(start 379.766322 -55.65013)
		(end 379.766322 -55.466742)
		(width 0.12954)
		(layer "F.Cu")
		(net "JTAG_TRC_PCH_PTI<2>")
	)
	(segment
		(start 350.578928 -17.449038)
		(end 350.449388 -17.319498)
		(width 0.12954)
		(layer "F.Cu")
		(net "JTAG_TRC_PCH_PTI<2>")
	)
	(segment
		(start 377.063 -42.215562)
		(end 377.19254 -42.086022)
		(width 0.12954)
		(layer "F.Cu")
		(net "JTAG_TRC_PCH_PTI<2>")
	)
	(segment
		(start 382.561338 -56.806338)
		(end 380.92253 -56.806338)
		(width 0.12954)
		(layer "F.Cu")
		(net "JTAG_TRC_PCH_PTI<2>")
	)
	(segment
		(start 355.808788 -18.008854)
		(end 355.679248 -17.879314)
		(width 0.12954)
		(layer "F.Cu")
		(net "JTAG_TRC_PCH_PTI<2>")
	)
	(segment
		(start 344.600022 -26.845006)
		(end 344.416888 -27.28722)
		(width 0.12954)
		(layer "F.Cu")
		(net "JTAG_TRC_PCH_PTI<2>")
	)
	(segment
		(start 356.446328 -17.319498)
		(end 356.316788 -17.449038)
		(width 0.12954)
		(layer "F.Cu")
		(net "JTAG_TRC_PCH_PTI<2>")
	)
	(segment
		(start 347.261688 -18.008854)
		(end 346.341954 -18.008854)
		(width 0.12954)
		(layer "F.Cu")
		(net "JTAG_TRC_PCH_PTI<2>")
	)
	(segment
		(start 377.19254 -40.432482)
		(end 377.063 -40.302942)
		(width 0.12954)
		(layer "F.Cu")
		(net "JTAG_TRC_PCH_PTI<2>")
	)
	(segment
		(start 350.070928 -17.319498)
		(end 349.941388 -17.449038)
		(width 0.12954)
		(layer "F.Cu")
		(net "JTAG_TRC_PCH_PTI<2>")
	)
	(segment
		(start 341.10041 -37.916612)
		(end 341.10041 -38.196012)
		(width 0.0889)
		(layer "F.Cu")
		(net "JTAG_TRC_PCH_PTI<2>")
	)
	(segment
		(start 348.795848 -17.319498)
		(end 348.666308 -17.449038)
		(width 0.12954)
		(layer "F.Cu")
		(net "JTAG_TRC_PCH_PTI<2>")
	)
	(segment
		(start 376.89536 -52.779168)
		(end 376.89536 -44.895262)
		(width 0.12954)
		(layer "F.Cu")
		(net "JTAG_TRC_PCH_PTI<2>")
	)
	(segment
		(start 354.404168 -17.879314)
		(end 354.404168 -17.449038)
		(width 0.12954)
		(layer "F.Cu")
		(net "JTAG_TRC_PCH_PTI<2>")
	)
	(segment
		(start 388.451598 -58.749946)
		(end 386.982716 -57.281064)
		(width 0.12954)
		(layer "F.Cu")
		(net "JTAG_TRC_PCH_PTI<2>")
	)
	(segment
		(start 356.316788 -17.449038)
		(end 356.316788 -17.879314)
		(width 0.12954)
		(layer "F.Cu")
		(net "JTAG_TRC_PCH_PTI<2>")
	)
	(segment
		(start 348.536768 -18.008854)
		(end 348.158308 -18.008854)
		(width 0.12954)
		(layer "F.Cu")
		(net "JTAG_TRC_PCH_PTI<2>")
	)
	(segment
		(start 353.129088 -17.879314)
		(end 353.129088 -17.449038)
		(width 0.12954)
		(layer "F.Cu")
		(net "JTAG_TRC_PCH_PTI<2>")
	)
	(segment
		(start 377.962922 -53.663342)
		(end 378.258578 -53.367686)
		(width 0.12954)
		(layer "F.Cu")
		(net "JTAG_TRC_PCH_PTI<2>")
	)
	(segment
		(start 377.807728 -52.916836)
		(end 377.512072 -53.212492)
		(width 0.12954)
		(layer "F.Cu")
		(net "JTAG_TRC_PCH_PTI<2>")
	)
	(segment
		(start 376.89536 -41.070022)
		(end 377.0249 -40.940482)
		(width 0.12954)
		(layer "F.Cu")
		(net "JTAG_TRC_PCH_PTI<2>")
	)
	(segment
		(start 350.449388 -17.319498)
		(end 350.070928 -17.319498)
		(width 0.12954)
		(layer "F.Cu")
		(net "JTAG_TRC_PCH_PTI<2>")
	)
	(segment
		(start 377.0249 -41.578022)
		(end 376.89536 -41.448482)
		(width 0.12954)
		(layer "F.Cu")
		(net "JTAG_TRC_PCH_PTI<2>")
	)
	(segment
		(start 352.491548 -17.879314)
		(end 352.362008 -18.008854)
		(width 0.12954)
		(layer "F.Cu")
		(net "JTAG_TRC_PCH_PTI<2>")
	)
	(segment
		(start 344.600022 -19.750786)
		(end 344.600022 -26.845006)
		(width 0.12954)
		(layer "F.Cu")
		(net "JTAG_TRC_PCH_PTI<2>")
	)
	(segment
		(start 341.564976 -36.200588)
		(end 341.147908 -36.617656)
		(width 0.0889)
		(layer "F.Cu")
		(net "JTAG_TRC_PCH_PTI<2>")
	)
	(segment
		(start 348.028768 -17.879314)
		(end 348.028768 -17.449038)
		(width 0.12954)
		(layer "F.Cu")
		(net "JTAG_TRC_PCH_PTI<2>")
	)
	(segment
		(start 376.89536 -44.895262)
		(end 377.0249 -44.765722)
		(width 0.12954)
		(layer "F.Cu")
		(net "JTAG_TRC_PCH_PTI<2>")
	)
	(segment
		(start 344.416888 -28.731718)
		(end 343.915238 -29.233368)
		(width 0.12954)
		(layer "F.Cu")
		(net "JTAG_TRC_PCH_PTI<2>")
	)
	(segment
		(start 377.19254 -41.707562)
		(end 377.063 -41.578022)
		(width 0.12954)
		(layer "F.Cu")
		(net "JTAG_TRC_PCH_PTI<2>")
	)
	(segment
		(start 378.864622 -54.74843)
		(end 378.864622 -54.565042)
		(width 0.12954)
		(layer "F.Cu")
		(net "JTAG_TRC_PCH_PTI<2>")
	)
	(segment
		(start 341.200994 -37.765482)
		(end 341.10041 -37.916612)
		(width 0.0889)
		(layer "F.Cu")
		(net "JTAG_TRC_PCH_PTI<2>")
	)
	(segment
		(start 379.794516 -54.720236)
		(end 379.611128 -54.720236)
		(width 0.12954)
		(layer "F.Cu")
		(net "JTAG_TRC_PCH_PTI<2>")
	)
	(segment
		(start 376.89536 -43.998642)
		(end 376.89536 -43.620182)
		(width 0.12954)
		(layer "F.Cu")
		(net "JTAG_TRC_PCH_PTI<2>")
	)
	(segment
		(start 355.041708 -17.879314)
		(end 354.912168 -18.008854)
		(width 0.12954)
		(layer "F.Cu")
		(net "JTAG_TRC_PCH_PTI<2>")
	)
	(segment
		(start 377.19254 -43.361102)
		(end 377.19254 -42.982642)
		(width 0.12954)
		(layer "F.Cu")
		(net "JTAG_TRC_PCH_PTI<2>")
	)
	(segment
		(start 349.174308 -17.319498)
		(end 348.795848 -17.319498)
		(width 0.12954)
		(layer "F.Cu")
		(net "JTAG_TRC_PCH_PTI<2>")
	)
	(segment
		(start 357.083868 -18.008854)
		(end 356.954328 -17.879314)
		(width 0.12954)
		(layer "F.Cu")
		(net "JTAG_TRC_PCH_PTI<2>")
	)
	(segment
		(start 353.258628 -18.008854)
		(end 353.129088 -17.879314)
		(width 0.12954)
		(layer "F.Cu")
		(net "JTAG_TRC_PCH_PTI<2>")
	)
	(segment
		(start 353.637088 -18.008854)
		(end 353.258628 -18.008854)
		(width 0.12954)
		(layer "F.Cu")
		(net "JTAG_TRC_PCH_PTI<2>")
	)
	(segment
		(start 350.708468 -18.008854)
		(end 350.578928 -17.879314)
		(width 0.12954)
		(layer "F.Cu")
		(net "JTAG_TRC_PCH_PTI<2>")
	)
	(segment
		(start 349.303848 -17.449038)
		(end 349.174308 -17.319498)
		(width 0.12954)
		(layer "F.Cu")
		(net "JTAG_TRC_PCH_PTI<2>")
	)
	(segment
		(start 352.491548 -17.449038)
		(end 352.491548 -17.879314)
		(width 0.12954)
		(layer "F.Cu")
		(net "JTAG_TRC_PCH_PTI<2>")
	)
	(segment
		(start 377.063 -40.940482)
		(end 377.19254 -40.810942)
		(width 0.12954)
		(layer "F.Cu")
		(net "JTAG_TRC_PCH_PTI<2>")
	)
	(segment
		(start 341.401908 -38.545008)
		(end 341.401908 -38.880288)
		(width 0.0889)
		(layer "F.Cu")
		(net "JTAG_TRC_PCH_PTI<2>")
	)
	(segment
		(start 379.315472 -55.015892)
		(end 379.132084 -55.015892)
		(width 0.12954)
		(layer "F.Cu")
		(net "JTAG_TRC_PCH_PTI<2>")
	)
	(segment
		(start 378.864622 -54.565042)
		(end 379.160278 -54.269386)
		(width 0.12954)
		(layer "F.Cu")
		(net "JTAG_TRC_PCH_PTI<2>")
	)
	(segment
		(start 355.679248 -17.449038)
		(end 355.549708 -17.319498)
		(width 0.12954)
		(layer "F.Cu")
		(net "JTAG_TRC_PCH_PTI<2>")
	)
	(segment
		(start 376.89536 -41.448482)
		(end 376.89536 -41.070022)
		(width 0.12954)
		(layer "F.Cu")
		(net "JTAG_TRC_PCH_PTI<2>")
	)
	(segment
		(start 348.666308 -17.449038)
		(end 348.666308 -17.879314)
		(width 0.12954)
		(layer "F.Cu")
		(net "JTAG_TRC_PCH_PTI<2>")
	)
	(segment
		(start 355.171248 -17.319498)
		(end 355.041708 -17.449038)
		(width 0.12954)
		(layer "F.Cu")
		(net "JTAG_TRC_PCH_PTI<2>")
	)
	(segment
		(start 379.611128 -54.720236)
		(end 379.315472 -55.015892)
		(width 0.12954)
		(layer "F.Cu")
		(net "JTAG_TRC_PCH_PTI<2>")
	)
	(segment
		(start 353.766628 -17.879314)
		(end 353.637088 -18.008854)
		(width 0.12954)
		(layer "F.Cu")
		(net "JTAG_TRC_PCH_PTI<2>")
	)
	(segment
		(start 378.258578 -53.184298)
		(end 377.991116 -52.916836)
		(width 0.12954)
		(layer "F.Cu")
		(net "JTAG_TRC_PCH_PTI<2>")
	)
	(via
		(at 383.544318 -57.281064)
		(size 0.508)
		(drill 0.254)
		(layers "F.Cu" "B.Cu")
		(net "JTAG_TRC_PCH_PTI<2>")
	)
	(segment
		(start 358.871774 -21.183346)
		(end 359.139236 -21.450808)
		(width 0.12954)
		(layer "F.Cu")
		(net "JTAG_TRC_PCH_PTI<1>")
	)
	(segment
		(start 368.578384 -30.412436)
		(end 368.845846 -30.679898)
		(width 0.12954)
		(layer "F.Cu")
		(net "JTAG_TRC_PCH_PTI<1>")
	)
	(segment
		(start 373.988584 -35.822636)
		(end 374.256046 -36.090098)
		(width 0.12954)
		(layer "F.Cu")
		(net "JTAG_TRC_PCH_PTI<1>")
	)
	(segment
		(start 373.298974 -35.610546)
		(end 373.566436 -35.878008)
		(width 0.12954)
		(layer "F.Cu")
		(net "JTAG_TRC_PCH_PTI<1>")
	)
	(segment
		(start 361.126024 -23.254208)
		(end 361.181396 -23.198836)
		(width 0.12954)
		(layer "F.Cu")
		(net "JTAG_TRC_PCH_PTI<1>")
	)
	(segment
		(start 376.469148 -55.35041)
		(end 376.973592 -54.845966)
		(width 0.12954)
		(layer "F.Cu")
		(net "JTAG_TRC_PCH_PTI<1>")
	)
	(segment
		(start 362.746036 -25.057608)
		(end 362.929424 -25.057608)
		(width 0.12954)
		(layer "F.Cu")
		(net "JTAG_TRC_PCH_PTI<1>")
	)
	(segment
		(start 359.828846 -21.846286)
		(end 359.773474 -21.901658)
		(width 0.12954)
		(layer "F.Cu")
		(net "JTAG_TRC_PCH_PTI<1>")
	)
	(segment
		(start 378.326142 -56.198516)
		(end 377.821698 -56.70296)
		(width 0.12954)
		(layer "F.Cu")
		(net "JTAG_TRC_PCH_PTI<1>")
	)
	(segment
		(start 367.437924 -29.566108)
		(end 367.493296 -29.510736)
		(width 0.12954)
		(layer "F.Cu")
		(net "JTAG_TRC_PCH_PTI<1>")
	)
	(segment
		(start 358.871774 -20.999958)
		(end 358.871774 -21.183346)
		(width 0.12954)
		(layer "F.Cu")
		(net "JTAG_TRC_PCH_PTI<1>")
	)
	(segment
		(start 367.676684 -29.510736)
		(end 367.944146 -29.778198)
		(width 0.12954)
		(layer "F.Cu")
		(net "JTAG_TRC_PCH_PTI<1>")
	)
	(segment
		(start 388.14375 -59.249818)
		(end 392.034776 -59.249818)
		(width 0.12954)
		(layer "F.Cu")
		(net "JTAG_TRC_PCH_PTI<1>")
	)
	(segment
		(start 382.228598 -57.969404)
		(end 382.228598 -58.509408)
		(width 0.12954)
		(layer "F.Cu")
		(net "JTAG_TRC_PCH_PTI<1>")
	)
	(segment
		(start 364.732824 -26.861008)
		(end 364.788196 -26.805636)
		(width 0.12954)
		(layer "F.Cu")
		(net "JTAG_TRC_PCH_PTI<1>")
	)
	(segment
		(start 365.451136 -27.762708)
		(end 365.634524 -27.762708)
		(width 0.12954)
		(layer "F.Cu")
		(net "JTAG_TRC_PCH_PTI<1>")
	)
	(segment
		(start 363.647736 -25.959308)
		(end 363.831124 -25.959308)
		(width 0.12954)
		(layer "F.Cu")
		(net "JTAG_TRC_PCH_PTI<1>")
	)
	(segment
		(start 366.774984 -28.609036)
		(end 367.042446 -28.876498)
		(width 0.12954)
		(layer "F.Cu")
		(net "JTAG_TRC_PCH_PTI<1>")
	)
	(segment
		(start 362.266484 -24.100536)
		(end 362.533946 -24.367998)
		(width 0.12954)
		(layer "F.Cu")
		(net "JTAG_TRC_PCH_PTI<1>")
	)
	(segment
		(start 358.927146 -20.944586)
		(end 358.871774 -20.999958)
		(width 0.12954)
		(layer "F.Cu")
		(net "JTAG_TRC_PCH_PTI<1>")
	)
	(segment
		(start 345.498166 -29.245814)
		(end 345.498166 -27.484832)
		(width 0.12954)
		(layer "F.Cu")
		(net "JTAG_TRC_PCH_PTI<1>")
	)
	(segment
		(start 374.706896 -36.724336)
		(end 374.890284 -36.724336)
		(width 0.12954)
		(layer "F.Cu")
		(net "JTAG_TRC_PCH_PTI<1>")
	)
	(segment
		(start 375.157746 -36.991798)
		(end 375.157746 -37.175186)
		(width 0.12954)
		(layer "F.Cu")
		(net "JTAG_TRC_PCH_PTI<1>")
	)
	(segment
		(start 369.296696 -31.314136)
		(end 369.480084 -31.314136)
		(width 0.12954)
		(layer "F.Cu")
		(net "JTAG_TRC_PCH_PTI<1>")
	)
	(segment
		(start 362.533946 -24.367998)
		(end 362.533946 -24.551386)
		(width 0.12954)
		(layer "F.Cu")
		(net "JTAG_TRC_PCH_PTI<1>")
	)
	(segment
		(start 381.461518 -58.638948)
		(end 381.591058 -58.509408)
		(width 0.12954)
		(layer "F.Cu")
		(net "JTAG_TRC_PCH_PTI<1>")
	)
	(segment
		(start 365.239046 -27.073098)
		(end 365.239046 -27.256486)
		(width 0.12954)
		(layer "F.Cu")
		(net "JTAG_TRC_PCH_PTI<1>")
	)
	(segment
		(start 381.083058 -58.638948)
		(end 381.461518 -58.638948)
		(width 0.12954)
		(layer "F.Cu")
		(net "JTAG_TRC_PCH_PTI<1>")
	)
	(segment
		(start 372.903496 -34.920936)
		(end 373.086884 -34.920936)
		(width 0.12954)
		(layer "F.Cu")
		(net "JTAG_TRC_PCH_PTI<1>")
	)
	(segment
		(start 361.844336 -24.155908)
		(end 362.027724 -24.155908)
		(width 0.12954)
		(layer "F.Cu")
		(net "JTAG_TRC_PCH_PTI<1>")
	)
	(segment
		(start 360.279696 -22.297136)
		(end 360.463084 -22.297136)
		(width 0.12954)
		(layer "F.Cu")
		(net "JTAG_TRC_PCH_PTI<1>")
	)
	(segment
		(start 368.339624 -30.467808)
		(end 368.394996 -30.412436)
		(width 0.12954)
		(layer "F.Cu")
		(net "JTAG_TRC_PCH_PTI<1>")
	)
	(segment
		(start 384.03276 -57.737248)
		(end 386.63118 -57.737248)
		(width 0.12954)
		(layer "F.Cu")
		(net "JTAG_TRC_PCH_PTI<1>")
	)
	(segment
		(start 342.71585 -36.185856)
		(end 342.823546 -36.185856)
		(width 0.0889)
		(layer "F.Cu")
		(net "JTAG_TRC_PCH_PTI<1>")
	)
	(segment
		(start 362.478574 -24.606758)
		(end 362.478574 -24.790146)
		(width 0.12954)
		(layer "F.Cu")
		(net "JTAG_TRC_PCH_PTI<1>")
	)
	(segment
		(start 358.237536 -20.549108)
		(end 358.420924 -20.549108)
		(width 0.12954)
		(layer "F.Cu")
		(net "JTAG_TRC_PCH_PTI<1>")
	)
	(segment
		(start 362.929424 -25.057608)
		(end 362.984796 -25.002236)
		(width 0.12954)
		(layer "F.Cu")
		(net "JTAG_TRC_PCH_PTI<1>")
	)
	(segment
		(start 377.875292 -55.747666)
		(end 378.05868 -55.747666)
		(width 0.12954)
		(layer "F.Cu")
		(net "JTAG_TRC_PCH_PTI<1>")
	)
	(segment
		(start 366.085374 -28.213558)
		(end 366.085374 -28.396946)
		(width 0.12954)
		(layer "F.Cu")
		(net "JTAG_TRC_PCH_PTI<1>")
	)
	(segment
		(start 378.723398 -57.60466)
		(end 378.723398 -57.788048)
		(width 0.12954)
		(layer "F.Cu")
		(net "JTAG_TRC_PCH_PTI<1>")
	)
	(segment
		(start 360.675174 -22.803358)
		(end 360.675174 -22.986746)
		(width 0.12954)
		(layer "F.Cu")
		(net "JTAG_TRC_PCH_PTI<1>")
	)
	(segment
		(start 377.18746 -56.25211)
		(end 377.370848 -56.25211)
		(width 0.12954)
		(layer "F.Cu")
		(net "JTAG_TRC_PCH_PTI<1>")
	)
	(segment
		(start 371.550946 -33.568386)
		(end 371.495574 -33.623758)
		(width 0.12954)
		(layer "F.Cu")
		(net "JTAG_TRC_PCH_PTI<1>")
	)
	(segment
		(start 361.632246 -23.649686)
		(end 361.576874 -23.705058)
		(width 0.12954)
		(layer "F.Cu")
		(net "JTAG_TRC_PCH_PTI<1>")
	)
	(segment
		(start 366.536224 -28.664408)
		(end 366.591596 -28.609036)
		(width 0.12954)
		(layer "F.Cu")
		(net "JTAG_TRC_PCH_PTI<1>")
	)
	(segment
		(start 364.281974 -26.593546)
		(end 364.549436 -26.861008)
		(width 0.12954)
		(layer "F.Cu")
		(net "JTAG_TRC_PCH_PTI<1>")
	)
	(segment
		(start 364.788196 -26.805636)
		(end 364.971584 -26.805636)
		(width 0.12954)
		(layer "F.Cu")
		(net "JTAG_TRC_PCH_PTI<1>")
	)
	(segment
		(start 383.13106 -58.638948)
		(end 383.13614 -58.633868)
		(width 0.12954)
		(layer "F.Cu")
		(net "JTAG_TRC_PCH_PTI<1>")
	)
	(segment
		(start 377.821698 -56.70296)
		(end 377.821698 -56.886348)
		(width 0.12954)
		(layer "F.Cu")
		(net "JTAG_TRC_PCH_PTI<1>")
	)
	(segment
		(start 357.574596 -19.592036)
		(end 357.757984 -19.592036)
		(width 0.12954)
		(layer "F.Cu")
		(net "JTAG_TRC_PCH_PTI<1>")
	)
	(segment
		(start 369.747546 -31.764986)
		(end 369.692174 -31.820358)
		(width 0.12954)
		(layer "F.Cu")
		(net "JTAG_TRC_PCH_PTI<1>")
	)
	(segment
		(start 360.730546 -22.747986)
		(end 360.675174 -22.803358)
		(width 0.12954)
		(layer "F.Cu")
		(net "JTAG_TRC_PCH_PTI<1>")
	)
	(segment
		(start 358.927146 -20.761198)
		(end 358.927146 -20.944586)
		(width 0.12954)
		(layer "F.Cu")
		(net "JTAG_TRC_PCH_PTI<1>")
	)
	(segment
		(start 374.256046 -36.090098)
		(end 374.256046 -36.273486)
		(width 0.12954)
		(layer "F.Cu")
		(net "JTAG_TRC_PCH_PTI<1>")
	)
	(segment
		(start 376.919998 -55.80126)
		(end 376.919998 -55.984648)
		(width 0.12954)
		(layer "F.Cu")
		(net "JTAG_TRC_PCH_PTI<1>")
	)
	(segment
		(start 367.042446 -28.876498)
		(end 367.042446 -29.059886)
		(width 0.12954)
		(layer "F.Cu")
		(net "JTAG_TRC_PCH_PTI<1>")
	)
	(segment
		(start 364.971584 -26.805636)
		(end 365.239046 -27.073098)
		(width 0.12954)
		(layer "F.Cu")
		(net "JTAG_TRC_PCH_PTI<1>")
	)
	(segment
		(start 370.143024 -32.271208)
		(end 370.198396 -32.215836)
		(width 0.12954)
		(layer "F.Cu")
		(net "JTAG_TRC_PCH_PTI<1>")
	)
	(segment
		(start 380.186438 -58.638948)
		(end 380.315978 -58.509408)
		(width 0.12954)
		(layer "F.Cu")
		(net "JTAG_TRC_PCH_PTI<1>")
	)
	(segment
		(start 342.314022 -37.683948)
		(end 342.314022 -37.302948)
		(width 0.0889)
		(layer "F.Cu")
		(net "JTAG_TRC_PCH_PTI<1>")
	)
	(segment
		(start 359.773474 -21.901658)
		(end 359.773474 -22.085046)
		(width 0.12954)
		(layer "F.Cu")
		(net "JTAG_TRC_PCH_PTI<1>")
	)
	(segment
		(start 357.519224 -19.647408)
		(end 357.574596 -19.592036)
		(width 0.12954)
		(layer "F.Cu")
		(net "JTAG_TRC_PCH_PTI<1>")
	)
	(segment
		(start 345.674442 -20.408392)
		(end 346.99956 -19.083274)
		(width 0.12954)
		(layer "F.Cu")
		(net "JTAG_TRC_PCH_PTI<1>")
	)
	(segment
		(start 369.747546 -31.581598)
		(end 369.747546 -31.764986)
		(width 0.12954)
		(layer "F.Cu")
		(net "JTAG_TRC_PCH_PTI<1>")
	)
	(segment
		(start 370.649246 -32.666686)
		(end 370.593874 -32.722058)
		(width 0.12954)
		(layer "F.Cu")
		(net "JTAG_TRC_PCH_PTI<1>")
	)
	(segment
		(start 361.576874 -23.705058)
		(end 361.576874 -23.888446)
		(width 0.12954)
		(layer "F.Cu")
		(net "JTAG_TRC_PCH_PTI<1>")
	)
	(segment
		(start 366.987074 -29.115258)
		(end 366.987074 -29.298646)
		(width 0.12954)
		(layer "F.Cu")
		(net "JTAG_TRC_PCH_PTI<1>")
	)
	(segment
		(start 379.227842 -57.100216)
		(end 378.723398 -57.60466)
		(width 0.12954)
		(layer "F.Cu")
		(net "JTAG_TRC_PCH_PTI<1>")
	)
	(segment
		(start 345.674442 -27.059128)
		(end 345.674442 -20.408392)
		(width 0.12954)
		(layer "F.Cu")
		(net "JTAG_TRC_PCH_PTI<1>")
	)
	(segment
		(start 386.63118 -57.737248)
		(end 388.14375 -59.249818)
		(width 0.12954)
		(layer "F.Cu")
		(net "JTAG_TRC_PCH_PTI<1>")
	)
	(segment
		(start 362.027724 -24.155908)
		(end 362.083096 -24.100536)
		(width 0.12954)
		(layer "F.Cu")
		(net "JTAG_TRC_PCH_PTI<1>")
	)
	(segment
		(start 381.591058 -58.509408)
		(end 381.591058 -57.969404)
		(width 0.12954)
		(layer "F.Cu")
		(net "JTAG_TRC_PCH_PTI<1>")
	)
	(segment
		(start 360.463084 -22.297136)
		(end 360.730546 -22.564598)
		(width 0.12954)
		(layer "F.Cu")
		(net "JTAG_TRC_PCH_PTI<1>")
	)
	(segment
		(start 361.364784 -23.198836)
		(end 361.632246 -23.466298)
		(width 0.12954)
		(layer "F.Cu")
		(net "JTAG_TRC_PCH_PTI<1>")
	)
	(segment
		(start 377.370848 -56.25211)
		(end 377.875292 -55.747666)
		(width 0.12954)
		(layer "F.Cu")
		(net "JTAG_TRC_PCH_PTI<1>")
	)
	(segment
		(start 356.771702 -19.083274)
		(end 357.335836 -19.647408)
		(width 0.12954)
		(layer "F.Cu")
		(net "JTAG_TRC_PCH_PTI<1>")
	)
	(segment
		(start 373.354346 -35.188398)
		(end 373.354346 -35.371786)
		(width 0.12954)
		(layer "F.Cu")
		(net "JTAG_TRC_PCH_PTI<1>")
	)
	(segment
		(start 372.452646 -34.286698)
		(end 372.452646 -34.470086)
		(width 0.12954)
		(layer "F.Cu")
		(net "JTAG_TRC_PCH_PTI<1>")
	)
	(segment
		(start 378.08916 -57.15381)
		(end 378.272548 -57.15381)
		(width 0.12954)
		(layer "F.Cu")
		(net "JTAG_TRC_PCH_PTI<1>")
	)
	(segment
		(start 368.790474 -31.102046)
		(end 369.057936 -31.369508)
		(width 0.12954)
		(layer "F.Cu")
		(net "JTAG_TRC_PCH_PTI<1>")
	)
	(segment
		(start 363.886496 -25.903936)
		(end 364.069884 -25.903936)
		(width 0.12954)
		(layer "F.Cu")
		(net "JTAG_TRC_PCH_PTI<1>")
	)
	(segment
		(start 359.139236 -21.450808)
		(end 359.322624 -21.450808)
		(width 0.12954)
		(layer "F.Cu")
		(net "JTAG_TRC_PCH_PTI<1>")
	)
	(segment
		(start 369.692174 -31.820358)
		(end 369.692174 -32.003746)
		(width 0.12954)
		(layer "F.Cu")
		(net "JTAG_TRC_PCH_PTI<1>")
	)
	(segment
		(start 360.040936 -22.352508)
		(end 360.224324 -22.352508)
		(width 0.12954)
		(layer "F.Cu")
		(net "JTAG_TRC_PCH_PTI<1>")
	)
	(segment
		(start 366.987074 -29.298646)
		(end 367.254536 -29.566108)
		(width 0.12954)
		(layer "F.Cu")
		(net "JTAG_TRC_PCH_PTI<1>")
	)
	(segment
		(start 371.283484 -33.117536)
		(end 371.550946 -33.384998)
		(width 0.12954)
		(layer "F.Cu")
		(net "JTAG_TRC_PCH_PTI<1>")
	)
	(segment
		(start 376.28576 -55.35041)
		(end 376.469148 -55.35041)
		(width 0.12954)
		(layer "F.Cu")
		(net "JTAG_TRC_PCH_PTI<1>")
	)
	(segment
		(start 380.823978 -57.839864)
		(end 380.953518 -57.969404)
		(width 0.12954)
		(layer "F.Cu")
		(net "JTAG_TRC_PCH_PTI<1>")
	)
	(segment
		(start 373.749824 -35.878008)
		(end 373.805196 -35.822636)
		(width 0.12954)
		(layer "F.Cu")
		(net "JTAG_TRC_PCH_PTI<1>")
	)
	(segment
		(start 367.254536 -29.566108)
		(end 367.437924 -29.566108)
		(width 0.12954)
		(layer "F.Cu")
		(net "JTAG_TRC_PCH_PTI<1>")
	)
	(segment
		(start 365.634524 -27.762708)
		(end 365.689896 -27.707336)
		(width 0.12954)
		(layer "F.Cu")
		(net "JTAG_TRC_PCH_PTI<1>")
	)
	(segment
		(start 381.720598 -57.839864)
		(end 382.099058 -57.839864)
		(width 0.12954)
		(layer "F.Cu")
		(net "JTAG_TRC_PCH_PTI<1>")
	)
	(segment
		(start 364.549436 -26.861008)
		(end 364.732824 -26.861008)
		(width 0.12954)
		(layer "F.Cu")
		(net "JTAG_TRC_PCH_PTI<1>")
	)
	(segment
		(start 379.574298 -58.638948)
		(end 380.186438 -58.638948)
		(width 0.12954)
		(layer "F.Cu")
		(net "JTAG_TRC_PCH_PTI<1>")
	)
	(segment
		(start 363.435646 -25.453086)
		(end 363.380274 -25.508458)
		(width 0.12954)
		(layer "F.Cu")
		(net "JTAG_TRC_PCH_PTI<1>")
	)
	(segment
		(start 365.873284 -27.707336)
		(end 366.140746 -27.974798)
		(width 0.12954)
		(layer "F.Cu")
		(net "JTAG_TRC_PCH_PTI<1>")
	)
	(segment
		(start 380.315978 -57.969404)
		(end 380.445518 -57.839864)
		(width 0.12954)
		(layer "F.Cu")
		(net "JTAG_TRC_PCH_PTI<1>")
	)
	(segment
		(start 368.790474 -30.918658)
		(end 368.790474 -31.102046)
		(width 0.12954)
		(layer "F.Cu")
		(net "JTAG_TRC_PCH_PTI<1>")
	)
	(segment
		(start 360.675174 -22.986746)
		(end 360.942636 -23.254208)
		(width 0.12954)
		(layer "F.Cu")
		(net "JTAG_TRC_PCH_PTI<1>")
	)
	(segment
		(start 380.315978 -58.509408)
		(end 380.315978 -57.969404)
		(width 0.12954)
		(layer "F.Cu")
		(net "JTAG_TRC_PCH_PTI<1>")
	)
	(segment
		(start 361.181396 -23.198836)
		(end 361.364784 -23.198836)
		(width 0.12954)
		(layer "F.Cu")
		(net "JTAG_TRC_PCH_PTI<1>")
	)
	(segment
		(start 359.322624 -21.450808)
		(end 359.377996 -21.395436)
		(width 0.12954)
		(layer "F.Cu")
		(net "JTAG_TRC_PCH_PTI<1>")
	)
	(segment
		(start 374.256046 -36.273486)
		(end 374.200674 -36.328858)
		(width 0.12954)
		(layer "F.Cu")
		(net "JTAG_TRC_PCH_PTI<1>")
	)
	(segment
		(start 365.239046 -27.256486)
		(end 365.183674 -27.311858)
		(width 0.12954)
		(layer "F.Cu")
		(net "JTAG_TRC_PCH_PTI<1>")
	)
	(segment
		(start 382.228598 -58.509408)
		(end 382.358138 -58.638948)
		(width 0.12954)
		(layer "F.Cu")
		(net "JTAG_TRC_PCH_PTI<1>")
	)
	(segment
		(start 369.241324 -31.369508)
		(end 369.296696 -31.314136)
		(width 0.12954)
		(layer "F.Cu")
		(net "JTAG_TRC_PCH_PTI<1>")
	)
	(segment
		(start 363.380274 -25.508458)
		(end 363.380274 -25.691846)
		(width 0.12954)
		(layer "F.Cu")
		(net "JTAG_TRC_PCH_PTI<1>")
	)
	(segment
		(start 375.82094 -38.133528)
		(end 375.82094 -54.88559)
		(width 0.12954)
		(layer "F.Cu")
		(net "JTAG_TRC_PCH_PTI<1>")
	)
	(segment
		(start 363.831124 -25.959308)
		(end 363.886496 -25.903936)
		(width 0.12954)
		(layer "F.Cu")
		(net "JTAG_TRC_PCH_PTI<1>")
	)
	(segment
		(start 375.157746 -37.175186)
		(end 375.10212 -37.230812)
		(width 0.12954)
		(layer "F.Cu")
		(net "JTAG_TRC_PCH_PTI<1>")
	)
	(segment
		(start 364.337346 -26.171398)
		(end 364.337346 -26.354786)
		(width 0.12954)
		(layer "F.Cu")
		(net "JTAG_TRC_PCH_PTI<1>")
	)
	(segment
		(start 359.828846 -21.662898)
		(end 359.828846 -21.846286)
		(width 0.12954)
		(layer "F.Cu")
		(net "JTAG_TRC_PCH_PTI<1>")
	)
	(segment
		(start 375.82094 -54.88559)
		(end 376.28576 -55.35041)
		(width 0.12954)
		(layer "F.Cu")
		(net "JTAG_TRC_PCH_PTI<1>")
	)
	(segment
		(start 365.183674 -27.495246)
		(end 365.451136 -27.762708)
		(width 0.12954)
		(layer "F.Cu")
		(net "JTAG_TRC_PCH_PTI<1>")
	)
	(segment
		(start 368.845846 -30.679898)
		(end 368.845846 -30.863286)
		(width 0.12954)
		(layer "F.Cu")
		(net "JTAG_TRC_PCH_PTI<1>")
	)
	(segment
		(start 366.140746 -28.158186)
		(end 366.085374 -28.213558)
		(width 0.12954)
		(layer "F.Cu")
		(net "JTAG_TRC_PCH_PTI<1>")
	)
	(segment
		(start 368.394996 -30.412436)
		(end 368.578384 -30.412436)
		(width 0.12954)
		(layer "F.Cu")
		(net "JTAG_TRC_PCH_PTI<1>")
	)
	(segment
		(start 374.200674 -36.328858)
		(end 374.200674 -36.512246)
		(width 0.12954)
		(layer "F.Cu")
		(net "JTAG_TRC_PCH_PTI<1>")
	)
	(segment
		(start 372.001796 -34.019236)
		(end 372.185184 -34.019236)
		(width 0.12954)
		(layer "F.Cu")
		(net "JTAG_TRC_PCH_PTI<1>")
	)
	(segment
		(start 380.953518 -58.509408)
		(end 381.083058 -58.638948)
		(width 0.12954)
		(layer "F.Cu")
		(net "JTAG_TRC_PCH_PTI<1>")
	)
	(segment
		(start 378.326142 -56.015128)
		(end 378.326142 -56.198516)
		(width 0.12954)
		(layer "F.Cu")
		(net "JTAG_TRC_PCH_PTI<1>")
	)
	(segment
		(start 362.984796 -25.002236)
		(end 363.168184 -25.002236)
		(width 0.12954)
		(layer "F.Cu")
		(net "JTAG_TRC_PCH_PTI<1>")
	)
	(segment
		(start 360.942636 -23.254208)
		(end 361.126024 -23.254208)
		(width 0.12954)
		(layer "F.Cu")
		(net "JTAG_TRC_PCH_PTI<1>")
	)
	(segment
		(start 378.05868 -55.747666)
		(end 378.326142 -56.015128)
		(width 0.12954)
		(layer "F.Cu")
		(net "JTAG_TRC_PCH_PTI<1>")
	)
	(segment
		(start 373.298974 -35.427158)
		(end 373.298974 -35.610546)
		(width 0.12954)
		(layer "F.Cu")
		(net "JTAG_TRC_PCH_PTI<1>")
	)
	(segment
		(start 343.147396 -35.862006)
		(end 343.147396 -35.423348)
		(width 0.0889)
		(layer "F.Cu")
		(net "JTAG_TRC_PCH_PTI<1>")
	)
	(segment
		(start 373.354346 -35.371786)
		(end 373.298974 -35.427158)
		(width 0.12954)
		(layer "F.Cu")
		(net "JTAG_TRC_PCH_PTI<1>")
	)
	(segment
		(start 368.845846 -30.863286)
		(end 368.790474 -30.918658)
		(width 0.12954)
		(layer "F.Cu")
		(net "JTAG_TRC_PCH_PTI<1>")
	)
	(segment
		(start 367.888774 -30.016958)
		(end 367.888774 -30.200346)
		(width 0.12954)
		(layer "F.Cu")
		(net "JTAG_TRC_PCH_PTI<1>")
	)
	(segment
		(start 377.424442 -55.113428)
		(end 377.424442 -55.296816)
		(width 0.12954)
		(layer "F.Cu")
		(net "JTAG_TRC_PCH_PTI<1>")
	)
	(segment
		(start 363.435646 -25.269698)
		(end 363.435646 -25.453086)
		(width 0.12954)
		(layer "F.Cu")
		(net "JTAG_TRC_PCH_PTI<1>")
	)
	(segment
		(start 383.13614 -58.633868)
		(end 384.03276 -57.737248)
		(width 0.12954)
		(layer "F.Cu")
		(net "JTAG_TRC_PCH_PTI<1>")
	)
	(segment
		(start 346.99956 -19.083274)
		(end 356.771702 -19.083274)
		(width 0.12954)
		(layer "F.Cu")
		(net "JTAG_TRC_PCH_PTI<1>")
	)
	(segment
		(start 359.773474 -22.085046)
		(end 360.040936 -22.352508)
		(width 0.12954)
		(layer "F.Cu")
		(net "JTAG_TRC_PCH_PTI<1>")
	)
	(segment
		(start 377.821698 -56.886348)
		(end 378.08916 -57.15381)
		(width 0.12954)
		(layer "F.Cu")
		(net "JTAG_TRC_PCH_PTI<1>")
	)
	(segment
		(start 358.025446 -19.859498)
		(end 358.025446 -20.042886)
		(width 0.12954)
		(layer "F.Cu")
		(net "JTAG_TRC_PCH_PTI<1>")
	)
	(segment
		(start 359.377996 -21.395436)
		(end 359.561384 -21.395436)
		(width 0.12954)
		(layer "F.Cu")
		(net "JTAG_TRC_PCH_PTI<1>")
	)
	(segment
		(start 357.970074 -20.281646)
		(end 358.237536 -20.549108)
		(width 0.12954)
		(layer "F.Cu")
		(net "JTAG_TRC_PCH_PTI<1>")
	)
	(segment
		(start 360.730546 -22.564598)
		(end 360.730546 -22.747986)
		(width 0.12954)
		(layer "F.Cu")
		(net "JTAG_TRC_PCH_PTI<1>")
	)
	(segment
		(start 380.445518 -57.839864)
		(end 380.823978 -57.839864)
		(width 0.12954)
		(layer "F.Cu")
		(net "JTAG_TRC_PCH_PTI<1>")
	)
	(segment
		(start 345.027504 -29.716476)
		(end 345.498166 -29.245814)
		(width 0.12954)
		(layer "F.Cu")
		(net "JTAG_TRC_PCH_PTI<1>")
	)
	(segment
		(start 377.15698 -54.845966)
		(end 377.424442 -55.113428)
		(width 0.12954)
		(layer "F.Cu")
		(net "JTAG_TRC_PCH_PTI<1>")
	)
	(segment
		(start 378.96038 -56.649366)
		(end 379.227842 -56.916828)
		(width 0.12954)
		(layer "F.Cu")
		(net "JTAG_TRC_PCH_PTI<1>")
	)
	(segment
		(start 343.147396 -35.423348)
		(end 343.264236 -35.306508)
		(width 0.0889)
		(layer "F.Cu")
		(net "JTAG_TRC_PCH_PTI<1>")
	)
	(segment
		(start 342.148414 -37.13734)
		(end 342.148414 -36.753292)
		(width 0.0889)
		(layer "F.Cu")
		(net "JTAG_TRC_PCH_PTI<1>")
	)
	(segment
		(start 370.593874 -32.905446)
		(end 370.861336 -33.172908)
		(width 0.12954)
		(layer "F.Cu")
		(net "JTAG_TRC_PCH_PTI<1>")
	)
	(segment
		(start 366.140746 -27.974798)
		(end 366.140746 -28.158186)
		(width 0.12954)
		(layer "F.Cu")
		(net "JTAG_TRC_PCH_PTI<1>")
	)
	(segment
		(start 367.944146 -29.961586)
		(end 367.888774 -30.016958)
		(width 0.12954)
		(layer "F.Cu")
		(net "JTAG_TRC_PCH_PTI<1>")
	)
	(segment
		(start 374.651524 -36.779708)
		(end 374.706896 -36.724336)
		(width 0.12954)
		(layer "F.Cu")
		(net "JTAG_TRC_PCH_PTI<1>")
	)
	(segment
		(start 372.185184 -34.019236)
		(end 372.452646 -34.286698)
		(width 0.12954)
		(layer "F.Cu")
		(net "JTAG_TRC_PCH_PTI<1>")
	)
	(segment
		(start 342.148414 -36.753292)
		(end 342.71585 -36.185856)
		(width 0.0889)
		(layer "F.Cu")
		(net "JTAG_TRC_PCH_PTI<1>")
	)
	(segment
		(start 342.823546 -36.185856)
		(end 343.147396 -35.862006)
		(width 0.0889)
		(layer "F.Cu")
		(net "JTAG_TRC_PCH_PTI<1>")
	)
	(segment
		(start 375.10212 -37.230812)
		(end 375.10212 -37.413692)
		(width 0.12954)
		(layer "F.Cu")
		(net "JTAG_TRC_PCH_PTI<1>")
	)
	(segment
		(start 360.224324 -22.352508)
		(end 360.279696 -22.297136)
		(width 0.12954)
		(layer "F.Cu")
		(net "JTAG_TRC_PCH_PTI<1>")
	)
	(segment
		(start 372.452646 -34.470086)
		(end 372.397274 -34.525458)
		(width 0.12954)
		(layer "F.Cu")
		(net "JTAG_TRC_PCH_PTI<1>")
	)
	(segment
		(start 358.659684 -20.493736)
		(end 358.927146 -20.761198)
		(width 0.12954)
		(layer "F.Cu")
		(net "JTAG_TRC_PCH_PTI<1>")
	)
	(segment
		(start 357.970074 -20.098258)
		(end 357.970074 -20.281646)
		(width 0.12954)
		(layer "F.Cu")
		(net "JTAG_TRC_PCH_PTI<1>")
	)
	(segment
		(start 369.959636 -32.271208)
		(end 370.143024 -32.271208)
		(width 0.12954)
		(layer "F.Cu")
		(net "JTAG_TRC_PCH_PTI<1>")
	)
	(segment
		(start 362.478574 -24.790146)
		(end 362.746036 -25.057608)
		(width 0.12954)
		(layer "F.Cu")
		(net "JTAG_TRC_PCH_PTI<1>")
	)
	(segment
		(start 364.337346 -26.354786)
		(end 364.281974 -26.410158)
		(width 0.12954)
		(layer "F.Cu")
		(net "JTAG_TRC_PCH_PTI<1>")
	)
	(segment
		(start 370.861336 -33.172908)
		(end 371.044724 -33.172908)
		(width 0.12954)
		(layer "F.Cu")
		(net "JTAG_TRC_PCH_PTI<1>")
	)
	(segment
		(start 380.953518 -57.969404)
		(end 380.953518 -58.509408)
		(width 0.12954)
		(layer "F.Cu")
		(net "JTAG_TRC_PCH_PTI<1>")
	)
	(segment
		(start 378.723398 -57.788048)
		(end 379.574298 -58.638948)
		(width 0.12954)
		(layer "F.Cu")
		(net "JTAG_TRC_PCH_PTI<1>")
	)
	(segment
		(start 342.314022 -37.302948)
		(end 342.148414 -37.13734)
		(width 0.0889)
		(layer "F.Cu")
		(net "JTAG_TRC_PCH_PTI<1>")
	)
	(segment
		(start 343.264236 -35.306508)
		(end 345.027504 -33.54324)
		(width 0.12954)
		(layer "F.Cu")
		(net "JTAG_TRC_PCH_PTI<1>")
	)
	(segment
		(start 369.057936 -31.369508)
		(end 369.241324 -31.369508)
		(width 0.12954)
		(layer "F.Cu")
		(net "JTAG_TRC_PCH_PTI<1>")
	)
	(segment
		(start 374.890284 -36.724336)
		(end 375.157746 -36.991798)
		(width 0.12954)
		(layer "F.Cu")
		(net "JTAG_TRC_PCH_PTI<1>")
	)
	(segment
		(start 358.476296 -20.493736)
		(end 358.659684 -20.493736)
		(width 0.12954)
		(layer "F.Cu")
		(net "JTAG_TRC_PCH_PTI<1>")
	)
	(segment
		(start 345.498166 -27.484832)
		(end 345.674442 -27.059128)
		(width 0.12954)
		(layer "F.Cu")
		(net "JTAG_TRC_PCH_PTI<1>")
	)
	(segment
		(start 362.083096 -24.100536)
		(end 362.266484 -24.100536)
		(width 0.12954)
		(layer "F.Cu")
		(net "JTAG_TRC_PCH_PTI<1>")
	)
	(segment
		(start 372.664736 -34.976308)
		(end 372.848124 -34.976308)
		(width 0.12954)
		(layer "F.Cu")
		(net "JTAG_TRC_PCH_PTI<1>")
	)
	(segment
		(start 359.561384 -21.395436)
		(end 359.828846 -21.662898)
		(width 0.12954)
		(layer "F.Cu")
		(net "JTAG_TRC_PCH_PTI<1>")
	)
	(segment
		(start 370.381784 -32.215836)
		(end 370.649246 -32.483298)
		(width 0.12954)
		(layer "F.Cu")
		(net "JTAG_TRC_PCH_PTI<1>")
	)
	(segment
		(start 379.227842 -56.916828)
		(end 379.227842 -57.100216)
		(width 0.12954)
		(layer "F.Cu")
		(net "JTAG_TRC_PCH_PTI<1>")
	)
	(segment
		(start 345.027504 -33.54324)
		(end 345.027504 -29.716476)
		(width 0.12954)
		(layer "F.Cu")
		(net "JTAG_TRC_PCH_PTI<1>")
	)
	(segment
		(start 366.591596 -28.609036)
		(end 366.774984 -28.609036)
		(width 0.12954)
		(layer "F.Cu")
		(net "JTAG_TRC_PCH_PTI<1>")
	)
	(segment
		(start 361.632246 -23.466298)
		(end 361.632246 -23.649686)
		(width 0.12954)
		(layer "F.Cu")
		(net "JTAG_TRC_PCH_PTI<1>")
	)
	(segment
		(start 371.946424 -34.074608)
		(end 372.001796 -34.019236)
		(width 0.12954)
		(layer "F.Cu")
		(net "JTAG_TRC_PCH_PTI<1>")
	)
	(segment
		(start 370.649246 -32.483298)
		(end 370.649246 -32.666686)
		(width 0.12954)
		(layer "F.Cu")
		(net "JTAG_TRC_PCH_PTI<1>")
	)
	(segment
		(start 367.042446 -29.059886)
		(end 366.987074 -29.115258)
		(width 0.12954)
		(layer "F.Cu")
		(net "JTAG_TRC_PCH_PTI<1>")
	)
	(segment
		(start 371.495574 -33.623758)
		(end 371.495574 -33.807146)
		(width 0.12954)
		(layer "F.Cu")
		(net "JTAG_TRC_PCH_PTI<1>")
	)
	(segment
		(start 378.272548 -57.15381)
		(end 378.776992 -56.649366)
		(width 0.12954)
		(layer "F.Cu")
		(net "JTAG_TRC_PCH_PTI<1>")
	)
	(segment
		(start 369.480084 -31.314136)
		(end 369.747546 -31.581598)
		(width 0.12954)
		(layer "F.Cu")
		(net "JTAG_TRC_PCH_PTI<1>")
	)
	(segment
		(start 365.183674 -27.311858)
		(end 365.183674 -27.495246)
		(width 0.12954)
		(layer "F.Cu")
		(net "JTAG_TRC_PCH_PTI<1>")
	)
	(segment
		(start 381.591058 -57.969404)
		(end 381.720598 -57.839864)
		(width 0.12954)
		(layer "F.Cu")
		(net "JTAG_TRC_PCH_PTI<1>")
	)
	(segment
		(start 357.335836 -19.647408)
		(end 357.519224 -19.647408)
		(width 0.12954)
		(layer "F.Cu")
		(net "JTAG_TRC_PCH_PTI<1>")
	)
	(segment
		(start 363.380274 -25.691846)
		(end 363.647736 -25.959308)
		(width 0.12954)
		(layer "F.Cu")
		(net "JTAG_TRC_PCH_PTI<1>")
	)
	(segment
		(start 357.757984 -19.592036)
		(end 358.025446 -19.859498)
		(width 0.12954)
		(layer "F.Cu")
		(net "JTAG_TRC_PCH_PTI<1>")
	)
	(segment
		(start 372.397274 -34.525458)
		(end 372.397274 -34.708846)
		(width 0.12954)
		(layer "F.Cu")
		(net "JTAG_TRC_PCH_PTI<1>")
	)
	(segment
		(start 377.424442 -55.296816)
		(end 376.919998 -55.80126)
		(width 0.12954)
		(layer "F.Cu")
		(net "JTAG_TRC_PCH_PTI<1>")
	)
	(segment
		(start 378.776992 -56.649366)
		(end 378.96038 -56.649366)
		(width 0.12954)
		(layer "F.Cu")
		(net "JTAG_TRC_PCH_PTI<1>")
	)
	(segment
		(start 365.689896 -27.707336)
		(end 365.873284 -27.707336)
		(width 0.12954)
		(layer "F.Cu")
		(net "JTAG_TRC_PCH_PTI<1>")
	)
	(segment
		(start 369.692174 -32.003746)
		(end 369.959636 -32.271208)
		(width 0.12954)
		(layer "F.Cu")
		(net "JTAG_TRC_PCH_PTI<1>")
	)
	(segment
		(start 366.352836 -28.664408)
		(end 366.536224 -28.664408)
		(width 0.12954)
		(layer "F.Cu")
		(net "JTAG_TRC_PCH_PTI<1>")
	)
	(segment
		(start 370.593874 -32.722058)
		(end 370.593874 -32.905446)
		(width 0.12954)
		(layer "F.Cu")
		(net "JTAG_TRC_PCH_PTI<1>")
	)
	(segment
		(start 382.099058 -57.839864)
		(end 382.228598 -57.969404)
		(width 0.12954)
		(layer "F.Cu")
		(net "JTAG_TRC_PCH_PTI<1>")
	)
	(segment
		(start 367.493296 -29.510736)
		(end 367.676684 -29.510736)
		(width 0.12954)
		(layer "F.Cu")
		(net "JTAG_TRC_PCH_PTI<1>")
	)
	(segment
		(start 364.069884 -25.903936)
		(end 364.337346 -26.171398)
		(width 0.12954)
		(layer "F.Cu")
		(net "JTAG_TRC_PCH_PTI<1>")
	)
	(segment
		(start 361.576874 -23.888446)
		(end 361.844336 -24.155908)
		(width 0.12954)
		(layer "F.Cu")
		(net "JTAG_TRC_PCH_PTI<1>")
	)
	(segment
		(start 374.200674 -36.512246)
		(end 374.468136 -36.779708)
		(width 0.12954)
		(layer "F.Cu")
		(net "JTAG_TRC_PCH_PTI<1>")
	)
	(segment
		(start 358.420924 -20.549108)
		(end 358.476296 -20.493736)
		(width 0.12954)
		(layer "F.Cu")
		(net "JTAG_TRC_PCH_PTI<1>")
	)
	(segment
		(start 371.100096 -33.117536)
		(end 371.283484 -33.117536)
		(width 0.12954)
		(layer "F.Cu")
		(net "JTAG_TRC_PCH_PTI<1>")
	)
	(segment
		(start 376.919998 -55.984648)
		(end 377.18746 -56.25211)
		(width 0.12954)
		(layer "F.Cu")
		(net "JTAG_TRC_PCH_PTI<1>")
	)
	(segment
		(start 370.198396 -32.215836)
		(end 370.381784 -32.215836)
		(width 0.12954)
		(layer "F.Cu")
		(net "JTAG_TRC_PCH_PTI<1>")
	)
	(segment
		(start 371.495574 -33.807146)
		(end 371.763036 -34.074608)
		(width 0.12954)
		(layer "F.Cu")
		(net "JTAG_TRC_PCH_PTI<1>")
	)
	(segment
		(start 374.468136 -36.779708)
		(end 374.651524 -36.779708)
		(width 0.12954)
		(layer "F.Cu")
		(net "JTAG_TRC_PCH_PTI<1>")
	)
	(segment
		(start 372.397274 -34.708846)
		(end 372.664736 -34.976308)
		(width 0.12954)
		(layer "F.Cu")
		(net "JTAG_TRC_PCH_PTI<1>")
	)
	(segment
		(start 373.086884 -34.920936)
		(end 373.354346 -35.188398)
		(width 0.12954)
		(layer "F.Cu")
		(net "JTAG_TRC_PCH_PTI<1>")
	)
	(segment
		(start 368.156236 -30.467808)
		(end 368.339624 -30.467808)
		(width 0.12954)
		(layer "F.Cu")
		(net "JTAG_TRC_PCH_PTI<1>")
	)
	(segment
		(start 371.044724 -33.172908)
		(end 371.100096 -33.117536)
		(width 0.12954)
		(layer "F.Cu")
		(net "JTAG_TRC_PCH_PTI<1>")
	)
	(segment
		(start 342.402414 -38.050216)
		(end 342.402414 -37.77234)
		(width 0.0889)
		(layer "F.Cu")
		(net "JTAG_TRC_PCH_PTI<1>")
	)
	(segment
		(start 382.358138 -58.638948)
		(end 383.13106 -58.638948)
		(width 0.12954)
		(layer "F.Cu")
		(net "JTAG_TRC_PCH_PTI<1>")
	)
	(segment
		(start 366.085374 -28.396946)
		(end 366.352836 -28.664408)
		(width 0.12954)
		(layer "F.Cu")
		(net "JTAG_TRC_PCH_PTI<1>")
	)
	(segment
		(start 367.944146 -29.778198)
		(end 367.944146 -29.961586)
		(width 0.12954)
		(layer "F.Cu")
		(net "JTAG_TRC_PCH_PTI<1>")
	)
	(segment
		(start 372.848124 -34.976308)
		(end 372.903496 -34.920936)
		(width 0.12954)
		(layer "F.Cu")
		(net "JTAG_TRC_PCH_PTI<1>")
	)
	(segment
		(start 358.025446 -20.042886)
		(end 357.970074 -20.098258)
		(width 0.12954)
		(layer "F.Cu")
		(net "JTAG_TRC_PCH_PTI<1>")
	)
	(segment
		(start 367.888774 -30.200346)
		(end 368.156236 -30.467808)
		(width 0.12954)
		(layer "F.Cu")
		(net "JTAG_TRC_PCH_PTI<1>")
	)
	(segment
		(start 371.550946 -33.384998)
		(end 371.550946 -33.568386)
		(width 0.12954)
		(layer "F.Cu")
		(net "JTAG_TRC_PCH_PTI<1>")
	)
	(segment
		(start 362.533946 -24.551386)
		(end 362.478574 -24.606758)
		(width 0.12954)
		(layer "F.Cu")
		(net "JTAG_TRC_PCH_PTI<1>")
	)
	(segment
		(start 342.402414 -37.77234)
		(end 342.314022 -37.683948)
		(width 0.0889)
		(layer "F.Cu")
		(net "JTAG_TRC_PCH_PTI<1>")
	)
	(segment
		(start 364.281974 -26.410158)
		(end 364.281974 -26.593546)
		(width 0.12954)
		(layer "F.Cu")
		(net "JTAG_TRC_PCH_PTI<1>")
	)
	(segment
		(start 375.10212 -37.413692)
		(end 375.82094 -38.133528)
		(width 0.12954)
		(layer "F.Cu")
		(net "JTAG_TRC_PCH_PTI<1>")
	)
	(segment
		(start 363.168184 -25.002236)
		(end 363.435646 -25.269698)
		(width 0.12954)
		(layer "F.Cu")
		(net "JTAG_TRC_PCH_PTI<1>")
	)
	(segment
		(start 376.973592 -54.845966)
		(end 377.15698 -54.845966)
		(width 0.12954)
		(layer "F.Cu")
		(net "JTAG_TRC_PCH_PTI<1>")
	)
	(segment
		(start 371.763036 -34.074608)
		(end 371.946424 -34.074608)
		(width 0.12954)
		(layer "F.Cu")
		(net "JTAG_TRC_PCH_PTI<1>")
	)
	(segment
		(start 373.805196 -35.822636)
		(end 373.988584 -35.822636)
		(width 0.12954)
		(layer "F.Cu")
		(net "JTAG_TRC_PCH_PTI<1>")
	)
	(segment
		(start 373.566436 -35.878008)
		(end 373.749824 -35.878008)
		(width 0.12954)
		(layer "F.Cu")
		(net "JTAG_TRC_PCH_PTI<1>")
	)
	(via
		(at 383.13614 -58.633868)
		(size 0.508)
		(drill 0.254)
		(layers "F.Cu" "B.Cu")
		(net "JTAG_TRC_PCH_PTI<1>")
	)
	(segment
		(start 337.504278 -25.909778)
		(end 337.1088 -26.305256)
		(width 0.12954)
		(layer "F.Cu")
		(net "JTAG_TRC_PCH_PTI<15>")
	)
	(segment
		(start 360.019346 -12.84478)
		(end 344.74023 -12.84478)
		(width 0.12954)
		(layer "F.Cu")
		(net "JTAG_TRC_PCH_PTI<15>")
	)
	(segment
		(start 389.154162 -41.979596)
		(end 360.019346 -12.84478)
		(width 0.12954)
		(layer "F.Cu")
		(net "JTAG_TRC_PCH_PTI<15>")
	)
	(segment
		(start 337.1088 -26.305256)
		(end 337.1088 -28.632658)
		(width 0.12954)
		(layer "F.Cu")
		(net "JTAG_TRC_PCH_PTI<15>")
	)
	(segment
		(start 390.689592 -43.515026)
		(end 390.689592 -43.332146)
		(width 0.12954)
		(layer "F.Cu")
		(net "JTAG_TRC_PCH_PTI<15>")
	)
	(segment
		(start 393.99464 -48.092868)
		(end 393.99464 -46.820074)
		(width 0.12954)
		(layer "F.Cu")
		(net "JTAG_TRC_PCH_PTI<15>")
	)
	(segment
		(start 336.687414 -36.931346)
		(end 336.687414 -37.204142)
		(width 0.0889)
		(layer "F.Cu")
		(net "JTAG_TRC_PCH_PTI<15>")
	)
	(segment
		(start 336.263234 -29.478224)
		(end 336.131916 -29.795216)
		(width 0.12954)
		(layer "F.Cu")
		(net "JTAG_TRC_PCH_PTI<15>")
	)
	(segment
		(start 391.343896 -41.959276)
		(end 391.161016 -41.959276)
		(width 0.12954)
		(layer "F.Cu")
		(net "JTAG_TRC_PCH_PTI<15>")
	)
	(segment
		(start 390.8806 -45.113194)
		(end 391.492486 -44.501308)
		(width 0.12954)
		(layer "F.Cu")
		(net "JTAG_TRC_PCH_PTI<15>")
	)
	(segment
		(start 336.530442 -31.206186)
		(end 336.530442 -33.910778)
		(width 0.0889)
		(layer "F.Cu")
		(net "JTAG_TRC_PCH_PTI<15>")
	)
	(segment
		(start 392.034776 -52.249832)
		(end 393.413996 -52.249832)
		(width 0.12954)
		(layer "F.Cu")
		(net "JTAG_TRC_PCH_PTI<15>")
	)
	(segment
		(start 336.899758 -38.138862)
		(end 336.899758 -38.465252)
		(width 0.0889)
		(layer "F.Cu")
		(net "JTAG_TRC_PCH_PTI<15>")
	)
	(segment
		(start 336.409284 -36.653216)
		(end 336.687414 -36.931346)
		(width 0.0889)
		(layer "F.Cu")
		(net "JTAG_TRC_PCH_PTI<15>")
	)
	(segment
		(start 391.943336 -44.952158)
		(end 391.33145 -45.564044)
		(width 0.12954)
		(layer "F.Cu")
		(net "JTAG_TRC_PCH_PTI<15>")
	)
	(segment
		(start 336.611468 -37.795962)
		(end 336.72018 -37.959284)
		(width 0.0889)
		(layer "F.Cu")
		(net "JTAG_TRC_PCH_PTI<15>")
	)
	(segment
		(start 390.710166 -41.508426)
		(end 390.710166 -41.325546)
		(width 0.12954)
		(layer "F.Cu")
		(net "JTAG_TRC_PCH_PTI<15>")
	)
	(segment
		(start 391.611866 -42.410126)
		(end 391.611866 -42.227246)
		(width 0.12954)
		(layer "F.Cu")
		(net "JTAG_TRC_PCH_PTI<15>")
	)
	(segment
		(start 338.462112 -19.122898)
		(end 338.462112 -25.465532)
		(width 0.12954)
		(layer "F.Cu")
		(net "JTAG_TRC_PCH_PTI<15>")
	)
	(segment
		(start 344.74023 -12.84478)
		(end 338.462112 -19.122898)
		(width 0.12954)
		(layer "F.Cu")
		(net "JTAG_TRC_PCH_PTI<15>")
	)
	(segment
		(start 391.148062 -45.564044)
		(end 390.8806 -45.296582)
		(width 0.12954)
		(layer "F.Cu")
		(net "JTAG_TRC_PCH_PTI<15>")
	)
	(segment
		(start 390.8806 -45.296582)
		(end 390.8806 -45.113194)
		(width 0.12954)
		(layer "F.Cu")
		(net "JTAG_TRC_PCH_PTI<15>")
	)
	(segment
		(start 393.99464 -46.820074)
		(end 392.126724 -44.952158)
		(width 0.12954)
		(layer "F.Cu")
		(net "JTAG_TRC_PCH_PTI<15>")
	)
	(segment
		(start 336.72018 -37.959284)
		(end 336.899758 -38.138862)
		(width 0.0889)
		(layer "F.Cu")
		(net "JTAG_TRC_PCH_PTI<15>")
	)
	(segment
		(start 390.442196 -41.057576)
		(end 390.259316 -41.057576)
		(width 0.12954)
		(layer "F.Cu")
		(net "JTAG_TRC_PCH_PTI<15>")
	)
	(segment
		(start 390.710166 -41.325546)
		(end 390.442196 -41.057576)
		(width 0.12954)
		(layer "F.Cu")
		(net "JTAG_TRC_PCH_PTI<15>")
	)
	(segment
		(start 390.055862 -42.881296)
		(end 389.787892 -42.613326)
		(width 0.12954)
		(layer "F.Cu")
		(net "JTAG_TRC_PCH_PTI<15>")
	)
	(segment
		(start 390.689592 -43.332146)
		(end 391.611866 -42.410126)
		(width 0.12954)
		(layer "F.Cu")
		(net "JTAG_TRC_PCH_PTI<15>")
	)
	(segment
		(start 336.530442 -33.910778)
		(end 336.409284 -34.031936)
		(width 0.0889)
		(layer "F.Cu")
		(net "JTAG_TRC_PCH_PTI<15>")
	)
	(segment
		(start 390.238742 -42.881296)
		(end 390.055862 -42.881296)
		(width 0.12954)
		(layer "F.Cu")
		(net "JTAG_TRC_PCH_PTI<15>")
	)
	(segment
		(start 336.131916 -30.244034)
		(end 336.530442 -31.206186)
		(width 0.0889)
		(layer "F.Cu")
		(net "JTAG_TRC_PCH_PTI<15>")
	)
	(segment
		(start 390.259316 -41.057576)
		(end 389.337042 -41.979596)
		(width 0.12954)
		(layer "F.Cu")
		(net "JTAG_TRC_PCH_PTI<15>")
	)
	(segment
		(start 392.126724 -44.952158)
		(end 391.943336 -44.952158)
		(width 0.12954)
		(layer "F.Cu")
		(net "JTAG_TRC_PCH_PTI<15>")
	)
	(segment
		(start 391.33145 -45.564044)
		(end 391.148062 -45.564044)
		(width 0.12954)
		(layer "F.Cu")
		(net "JTAG_TRC_PCH_PTI<15>")
	)
	(segment
		(start 391.492486 -44.501308)
		(end 391.492486 -44.31792)
		(width 0.12954)
		(layer "F.Cu")
		(net "JTAG_TRC_PCH_PTI<15>")
	)
	(segment
		(start 389.787892 -42.430446)
		(end 390.710166 -41.508426)
		(width 0.12954)
		(layer "F.Cu")
		(net "JTAG_TRC_PCH_PTI<15>")
	)
	(segment
		(start 338.017866 -25.909778)
		(end 337.504278 -25.909778)
		(width 0.12954)
		(layer "F.Cu")
		(net "JTAG_TRC_PCH_PTI<15>")
	)
	(segment
		(start 389.337042 -41.979596)
		(end 389.154162 -41.979596)
		(width 0.12954)
		(layer "F.Cu")
		(net "JTAG_TRC_PCH_PTI<15>")
	)
	(segment
		(start 393.413996 -52.249832)
		(end 393.99464 -51.669188)
		(width 0.12954)
		(layer "F.Cu")
		(net "JTAG_TRC_PCH_PTI<15>")
	)
	(segment
		(start 389.787892 -42.613326)
		(end 389.787892 -42.430446)
		(width 0.12954)
		(layer "F.Cu")
		(net "JTAG_TRC_PCH_PTI<15>")
	)
	(segment
		(start 391.611866 -42.227246)
		(end 391.343896 -41.959276)
		(width 0.12954)
		(layer "F.Cu")
		(net "JTAG_TRC_PCH_PTI<15>")
	)
	(segment
		(start 336.131916 -29.795216)
		(end 336.131916 -30.244034)
		(width 0.12954)
		(layer "F.Cu")
		(net "JTAG_TRC_PCH_PTI<15>")
	)
	(segment
		(start 337.1088 -28.632658)
		(end 336.263234 -29.478224)
		(width 0.12954)
		(layer "F.Cu")
		(net "JTAG_TRC_PCH_PTI<15>")
	)
	(segment
		(start 391.492486 -44.31792)
		(end 390.689592 -43.515026)
		(width 0.12954)
		(layer "F.Cu")
		(net "JTAG_TRC_PCH_PTI<15>")
	)
	(segment
		(start 391.161016 -41.959276)
		(end 390.238742 -42.881296)
		(width 0.12954)
		(layer "F.Cu")
		(net "JTAG_TRC_PCH_PTI<15>")
	)
	(segment
		(start 393.99464 -51.669188)
		(end 393.99464 -48.092868)
		(width 0.12954)
		(layer "F.Cu")
		(net "JTAG_TRC_PCH_PTI<15>")
	)
	(segment
		(start 336.687414 -37.204142)
		(end 336.611468 -37.462206)
		(width 0.0889)
		(layer "F.Cu")
		(net "JTAG_TRC_PCH_PTI<15>")
	)
	(segment
		(start 336.409284 -34.031936)
		(end 336.409284 -36.653216)
		(width 0.0889)
		(layer "F.Cu")
		(net "JTAG_TRC_PCH_PTI<15>")
	)
	(segment
		(start 338.462112 -25.465532)
		(end 338.017866 -25.909778)
		(width 0.12954)
		(layer "F.Cu")
		(net "JTAG_TRC_PCH_PTI<15>")
	)
	(segment
		(start 336.611468 -37.462206)
		(end 336.611468 -37.795962)
		(width 0.0889)
		(layer "F.Cu")
		(net "JTAG_TRC_PCH_PTI<15>")
	)
	(via
		(at 393.99464 -48.092868)
		(size 0.508)
		(drill 0.254)
		(layers "F.Cu" "B.Cu")
		(net "JTAG_TRC_PCH_PTI<15>")
	)
	(segment
		(start 388.544562 -42.41165)
		(end 388.544562 -43.670474)
		(width 0.12954)
		(layer "F.Cu")
		(net "JTAG_TRC_PCH_PTI<14>")
	)
	(segment
		(start 339.198458 -25.883616)
		(end 339.198458 -19.400266)
		(width 0.12954)
		(layer "F.Cu")
		(net "JTAG_TRC_PCH_PTI<14>")
	)
	(segment
		(start 389.587232 -46.479714)
		(end 389.587232 -46.858174)
		(width 0.12954)
		(layer "F.Cu")
		(net "JTAG_TRC_PCH_PTI<14>")
	)
	(segment
		(start 388.674102 -44.437554)
		(end 388.544562 -44.567094)
		(width 0.12954)
		(layer "F.Cu")
		(net "JTAG_TRC_PCH_PTI<14>")
	)
	(segment
		(start 337.246214 -36.188396)
		(end 337.246214 -32.222948)
		(width 0.0889)
		(layer "F.Cu")
		(net "JTAG_TRC_PCH_PTI<14>")
	)
	(segment
		(start 337.693254 -30.638496)
		(end 337.693254 -29.57703)
		(width 0.12954)
		(layer "F.Cu")
		(net "JTAG_TRC_PCH_PTI<14>")
	)
	(segment
		(start 388.544562 -44.945554)
		(end 388.674102 -45.075094)
		(width 0.12954)
		(layer "F.Cu")
		(net "JTAG_TRC_PCH_PTI<14>")
	)
	(segment
		(start 339.198458 -19.400266)
		(end 345.017598 -13.581126)
		(width 0.12954)
		(layer "F.Cu")
		(net "JTAG_TRC_PCH_PTI<14>")
	)
	(segment
		(start 337.400138 -37.832792)
		(end 337.400138 -36.34232)
		(width 0.0889)
		(layer "F.Cu")
		(net "JTAG_TRC_PCH_PTI<14>")
	)
	(segment
		(start 337.400138 -36.34232)
		(end 337.246214 -36.188396)
		(width 0.0889)
		(layer "F.Cu")
		(net "JTAG_TRC_PCH_PTI<14>")
	)
	(segment
		(start 389.457692 -44.437554)
		(end 388.674102 -44.437554)
		(width 0.12954)
		(layer "F.Cu")
		(net "JTAG_TRC_PCH_PTI<14>")
	)
	(segment
		(start 389.587232 -45.204634)
		(end 389.587232 -45.583094)
		(width 0.12954)
		(layer "F.Cu")
		(net "JTAG_TRC_PCH_PTI<14>")
	)
	(segment
		(start 388.544562 -45.842174)
		(end 388.544562 -46.220634)
		(width 0.12954)
		(layer "F.Cu")
		(net "JTAG_TRC_PCH_PTI<14>")
	)
	(segment
		(start 388.544562 -47.729394)
		(end 387.89991 -48.374046)
		(width 0.12954)
		(layer "F.Cu")
		(net "JTAG_TRC_PCH_PTI<14>")
	)
	(segment
		(start 387.89991 -48.374046)
		(end 386.363464 -48.374046)
		(width 0.12954)
		(layer "F.Cu")
		(net "JTAG_TRC_PCH_PTI<14>")
	)
	(segment
		(start 389.083296 -52.749958)
		(end 392.034776 -52.749958)
		(width 0.12954)
		(layer "F.Cu")
		(net "JTAG_TRC_PCH_PTI<14>")
	)
	(segment
		(start 337.399884 -37.832792)
		(end 337.400138 -37.832792)
		(width 0.0889)
		(layer "F.Cu")
		(net "JTAG_TRC_PCH_PTI<14>")
	)
	(segment
		(start 389.587232 -43.929554)
		(end 389.587232 -44.308014)
		(width 0.12954)
		(layer "F.Cu")
		(net "JTAG_TRC_PCH_PTI<14>")
	)
	(segment
		(start 337.399884 -38.050216)
		(end 337.399884 -37.832792)
		(width 0.0889)
		(layer "F.Cu")
		(net "JTAG_TRC_PCH_PTI<14>")
	)
	(segment
		(start 388.674102 -43.800014)
		(end 389.457692 -43.800014)
		(width 0.12954)
		(layer "F.Cu")
		(net "JTAG_TRC_PCH_PTI<14>")
	)
	(segment
		(start 389.587232 -44.308014)
		(end 389.457692 -44.437554)
		(width 0.12954)
		(layer "F.Cu")
		(net "JTAG_TRC_PCH_PTI<14>")
	)
	(segment
		(start 337.693254 -29.57703)
		(end 338.591652 -28.678632)
		(width 0.12954)
		(layer "F.Cu")
		(net "JTAG_TRC_PCH_PTI<14>")
	)
	(segment
		(start 389.457692 -46.350174)
		(end 389.587232 -46.479714)
		(width 0.12954)
		(layer "F.Cu")
		(net "JTAG_TRC_PCH_PTI<14>")
	)
	(segment
		(start 388.544562 -47.117254)
		(end 388.544562 -47.729394)
		(width 0.12954)
		(layer "F.Cu")
		(net "JTAG_TRC_PCH_PTI<14>")
	)
	(segment
		(start 338.591652 -28.678632)
		(end 338.591652 -26.490422)
		(width 0.12954)
		(layer "F.Cu")
		(net "JTAG_TRC_PCH_PTI<14>")
	)
	(segment
		(start 388.544562 -43.670474)
		(end 388.674102 -43.800014)
		(width 0.12954)
		(layer "F.Cu")
		(net "JTAG_TRC_PCH_PTI<14>")
	)
	(segment
		(start 337.287616 -31.044134)
		(end 337.693254 -30.638496)
		(width 0.12954)
		(layer "F.Cu")
		(net "JTAG_TRC_PCH_PTI<14>")
	)
	(segment
		(start 337.246214 -32.222948)
		(end 337.287616 -32.181546)
		(width 0.0889)
		(layer "F.Cu")
		(net "JTAG_TRC_PCH_PTI<14>")
	)
	(segment
		(start 384.63982 -48.87214)
		(end 384.63982 -49.897792)
		(width 0.12954)
		(layer "F.Cu")
		(net "JTAG_TRC_PCH_PTI<14>")
	)
	(segment
		(start 389.457692 -46.987714)
		(end 388.674102 -46.987714)
		(width 0.12954)
		(layer "F.Cu")
		(net "JTAG_TRC_PCH_PTI<14>")
	)
	(segment
		(start 389.457692 -45.075094)
		(end 389.587232 -45.204634)
		(width 0.12954)
		(layer "F.Cu")
		(net "JTAG_TRC_PCH_PTI<14>")
	)
	(segment
		(start 389.457692 -43.800014)
		(end 389.587232 -43.929554)
		(width 0.12954)
		(layer "F.Cu")
		(net "JTAG_TRC_PCH_PTI<14>")
	)
	(segment
		(start 345.017598 -13.581126)
		(end 359.714038 -13.581126)
		(width 0.12954)
		(layer "F.Cu")
		(net "JTAG_TRC_PCH_PTI<14>")
	)
	(segment
		(start 386.363464 -48.374046)
		(end 386.34162 -48.352202)
		(width 0.12954)
		(layer "F.Cu")
		(net "JTAG_TRC_PCH_PTI<14>")
	)
	(segment
		(start 389.587232 -46.858174)
		(end 389.457692 -46.987714)
		(width 0.12954)
		(layer "F.Cu")
		(net "JTAG_TRC_PCH_PTI<14>")
	)
	(segment
		(start 386.34162 -48.352202)
		(end 385.159758 -48.352202)
		(width 0.12954)
		(layer "F.Cu")
		(net "JTAG_TRC_PCH_PTI<14>")
	)
	(segment
		(start 388.544562 -44.567094)
		(end 388.544562 -44.945554)
		(width 0.12954)
		(layer "F.Cu")
		(net "JTAG_TRC_PCH_PTI<14>")
	)
	(segment
		(start 384.63982 -49.897792)
		(end 387.491986 -52.749958)
		(width 0.12954)
		(layer "F.Cu")
		(net "JTAG_TRC_PCH_PTI<14>")
	)
	(segment
		(start 389.587232 -45.583094)
		(end 389.457692 -45.712634)
		(width 0.12954)
		(layer "F.Cu")
		(net "JTAG_TRC_PCH_PTI<14>")
	)
	(segment
		(start 385.159758 -48.352202)
		(end 384.63982 -48.87214)
		(width 0.12954)
		(layer "F.Cu")
		(net "JTAG_TRC_PCH_PTI<14>")
	)
	(segment
		(start 388.674102 -46.350174)
		(end 389.457692 -46.350174)
		(width 0.12954)
		(layer "F.Cu")
		(net "JTAG_TRC_PCH_PTI<14>")
	)
	(segment
		(start 388.544562 -46.220634)
		(end 388.674102 -46.350174)
		(width 0.12954)
		(layer "F.Cu")
		(net "JTAG_TRC_PCH_PTI<14>")
	)
	(segment
		(start 389.457692 -45.712634)
		(end 388.674102 -45.712634)
		(width 0.12954)
		(layer "F.Cu")
		(net "JTAG_TRC_PCH_PTI<14>")
	)
	(segment
		(start 388.674102 -45.712634)
		(end 388.544562 -45.842174)
		(width 0.12954)
		(layer "F.Cu")
		(net "JTAG_TRC_PCH_PTI<14>")
	)
	(segment
		(start 337.287616 -32.181546)
		(end 337.287616 -31.897828)
		(width 0.0889)
		(layer "F.Cu")
		(net "JTAG_TRC_PCH_PTI<14>")
	)
	(segment
		(start 388.674102 -45.075094)
		(end 389.457692 -45.075094)
		(width 0.12954)
		(layer "F.Cu")
		(net "JTAG_TRC_PCH_PTI<14>")
	)
	(segment
		(start 359.714038 -13.581126)
		(end 388.544562 -42.41165)
		(width 0.12954)
		(layer "F.Cu")
		(net "JTAG_TRC_PCH_PTI<14>")
	)
	(segment
		(start 388.674102 -46.987714)
		(end 388.544562 -47.117254)
		(width 0.12954)
		(layer "F.Cu")
		(net "JTAG_TRC_PCH_PTI<14>")
	)
	(segment
		(start 337.287616 -31.897828)
		(end 337.287616 -31.044134)
		(width 0.12954)
		(layer "F.Cu")
		(net "JTAG_TRC_PCH_PTI<14>")
	)
	(segment
		(start 338.591652 -26.490422)
		(end 339.198458 -25.883616)
		(width 0.12954)
		(layer "F.Cu")
		(net "JTAG_TRC_PCH_PTI<14>")
	)
	(segment
		(start 387.491986 -52.749958)
		(end 389.083296 -52.749958)
		(width 0.12954)
		(layer "F.Cu")
		(net "JTAG_TRC_PCH_PTI<14>")
	)
	(via
		(at 389.083296 -52.749958)
		(size 0.508)
		(drill 0.254)
		(layers "F.Cu" "B.Cu")
		(net "JTAG_TRC_PCH_PTI<14>")
	)
	(segment
		(start 338.949792 -28.830778)
		(end 338.949792 -26.639266)
		(width 0.12954)
		(layer "F.Cu")
		(net "JTAG_TRC_PCH_PTI<13>")
	)
	(segment
		(start 387.079998 -46.905418)
		(end 386.950458 -47.034958)
		(width 0.12954)
		(layer "F.Cu")
		(net "JTAG_TRC_PCH_PTI<13>")
	)
	(segment
		(start 339.617558 -19.48815)
		(end 345.105482 -14.000226)
		(width 0.12954)
		(layer "F.Cu")
		(net "JTAG_TRC_PCH_PTI<13>")
	)
	(segment
		(start 386.950458 -41.410382)
		(end 386.950458 -42.313098)
		(width 0.12954)
		(layer "F.Cu")
		(net "JTAG_TRC_PCH_PTI<13>")
	)
	(segment
		(start 387.74878 -42.442638)
		(end 387.87832 -42.572178)
		(width 0.12954)
		(layer "F.Cu")
		(net "JTAG_TRC_PCH_PTI<13>")
	)
	(segment
		(start 386.950458 -42.313098)
		(end 387.079998 -42.442638)
		(width 0.12954)
		(layer "F.Cu")
		(net "JTAG_TRC_PCH_PTI<13>")
	)
	(segment
		(start 387.87832 -45.500798)
		(end 387.74878 -45.630338)
		(width 0.12954)
		(layer "F.Cu")
		(net "JTAG_TRC_PCH_PTI<13>")
	)
	(segment
		(start 386.950458 -43.588178)
		(end 387.079998 -43.717718)
		(width 0.12954)
		(layer "F.Cu")
		(net "JTAG_TRC_PCH_PTI<13>")
	)
	(segment
		(start 387.820916 -46.905418)
		(end 387.079998 -46.905418)
		(width 0.12954)
		(layer "F.Cu")
		(net "JTAG_TRC_PCH_PTI<13>")
	)
	(segment
		(start 337.605878 -37.741606)
		(end 337.605878 -36.24199)
		(width 0.0889)
		(layer "F.Cu")
		(net "JTAG_TRC_PCH_PTI<13>")
	)
	(segment
		(start 386.718048 -47.879508)
		(end 384.557778 -47.879508)
		(width 0.12954)
		(layer "F.Cu")
		(net "JTAG_TRC_PCH_PTI<13>")
	)
	(segment
		(start 337.900264 -38.465252)
		(end 337.900264 -38.184074)
		(width 0.0889)
		(layer "F.Cu")
		(net "JTAG_TRC_PCH_PTI<13>")
	)
	(segment
		(start 387.87832 -42.572178)
		(end 387.87832 -42.950638)
		(width 0.12954)
		(layer "F.Cu")
		(net "JTAG_TRC_PCH_PTI<13>")
	)
	(segment
		(start 387.079998 -43.717718)
		(end 387.74878 -43.717718)
		(width 0.12954)
		(layer "F.Cu")
		(net "JTAG_TRC_PCH_PTI<13>")
	)
	(segment
		(start 384.129026 -49.893982)
		(end 387.484874 -53.24983)
		(width 0.12954)
		(layer "F.Cu")
		(net "JTAG_TRC_PCH_PTI<13>")
	)
	(segment
		(start 387.079998 -45.630338)
		(end 386.950458 -45.759878)
		(width 0.12954)
		(layer "F.Cu")
		(net "JTAG_TRC_PCH_PTI<13>")
	)
	(segment
		(start 337.579716 -32.229552)
		(end 337.579716 -31.897828)
		(width 0.0889)
		(layer "F.Cu")
		(net "JTAG_TRC_PCH_PTI<13>")
	)
	(segment
		(start 387.74878 -43.080178)
		(end 387.079998 -43.080178)
		(width 0.12954)
		(layer "F.Cu")
		(net "JTAG_TRC_PCH_PTI<13>")
	)
	(segment
		(start 387.87832 -45.122338)
		(end 387.87832 -45.500798)
		(width 0.12954)
		(layer "F.Cu")
		(net "JTAG_TRC_PCH_PTI<13>")
	)
	(segment
		(start 387.079998 -44.992798)
		(end 387.74878 -44.992798)
		(width 0.12954)
		(layer "F.Cu")
		(net "JTAG_TRC_PCH_PTI<13>")
	)
	(segment
		(start 384.129026 -48.30826)
		(end 384.129026 -49.893982)
		(width 0.12954)
		(layer "F.Cu")
		(net "JTAG_TRC_PCH_PTI<13>")
	)
	(segment
		(start 337.43646 -36.072572)
		(end 337.43646 -32.372808)
		(width 0.0889)
		(layer "F.Cu")
		(net "JTAG_TRC_PCH_PTI<13>")
	)
	(segment
		(start 387.079998 -43.080178)
		(end 386.950458 -43.209718)
		(width 0.12954)
		(layer "F.Cu")
		(net "JTAG_TRC_PCH_PTI<13>")
	)
	(segment
		(start 337.43646 -32.372808)
		(end 337.579716 -32.229552)
		(width 0.0889)
		(layer "F.Cu")
		(net "JTAG_TRC_PCH_PTI<13>")
	)
	(segment
		(start 387.953758 -46.772576)
		(end 387.820916 -46.905418)
		(width 0.12954)
		(layer "F.Cu")
		(net "JTAG_TRC_PCH_PTI<13>")
	)
	(segment
		(start 387.87832 -42.950638)
		(end 387.74878 -43.080178)
		(width 0.12954)
		(layer "F.Cu")
		(net "JTAG_TRC_PCH_PTI<13>")
	)
	(segment
		(start 337.579716 -31.380684)
		(end 338.051394 -30.909006)
		(width 0.12954)
		(layer "F.Cu")
		(net "JTAG_TRC_PCH_PTI<13>")
	)
	(segment
		(start 387.953758 -46.38548)
		(end 387.953758 -46.772576)
		(width 0.12954)
		(layer "F.Cu")
		(net "JTAG_TRC_PCH_PTI<13>")
	)
	(segment
		(start 384.557778 -47.879508)
		(end 384.129026 -48.30826)
		(width 0.12954)
		(layer "F.Cu")
		(net "JTAG_TRC_PCH_PTI<13>")
	)
	(segment
		(start 386.950458 -45.759878)
		(end 386.950458 -46.138338)
		(width 0.12954)
		(layer "F.Cu")
		(net "JTAG_TRC_PCH_PTI<13>")
	)
	(segment
		(start 338.051394 -30.909006)
		(end 338.051394 -29.729176)
		(width 0.12954)
		(layer "F.Cu")
		(net "JTAG_TRC_PCH_PTI<13>")
	)
	(segment
		(start 387.079998 -46.267878)
		(end 387.836156 -46.267878)
		(width 0.12954)
		(layer "F.Cu")
		(net "JTAG_TRC_PCH_PTI<13>")
	)
	(segment
		(start 387.87832 -44.225718)
		(end 387.74878 -44.355258)
		(width 0.12954)
		(layer "F.Cu")
		(net "JTAG_TRC_PCH_PTI<13>")
	)
	(segment
		(start 386.950458 -47.034958)
		(end 386.950458 -47.647098)
		(width 0.12954)
		(layer "F.Cu")
		(net "JTAG_TRC_PCH_PTI<13>")
	)
	(segment
		(start 338.949792 -26.639266)
		(end 339.617558 -25.9715)
		(width 0.12954)
		(layer "F.Cu")
		(net "JTAG_TRC_PCH_PTI<13>")
	)
	(segment
		(start 387.836156 -46.267878)
		(end 387.953758 -46.38548)
		(width 0.12954)
		(layer "F.Cu")
		(net "JTAG_TRC_PCH_PTI<13>")
	)
	(segment
		(start 337.579716 -31.897828)
		(end 337.579716 -31.380684)
		(width 0.12954)
		(layer "F.Cu")
		(net "JTAG_TRC_PCH_PTI<13>")
	)
	(segment
		(start 339.617558 -25.9715)
		(end 339.617558 -19.48815)
		(width 0.12954)
		(layer "F.Cu")
		(net "JTAG_TRC_PCH_PTI<13>")
	)
	(segment
		(start 387.74878 -45.630338)
		(end 387.079998 -45.630338)
		(width 0.12954)
		(layer "F.Cu")
		(net "JTAG_TRC_PCH_PTI<13>")
	)
	(segment
		(start 386.950458 -47.647098)
		(end 386.718048 -47.879508)
		(width 0.12954)
		(layer "F.Cu")
		(net "JTAG_TRC_PCH_PTI<13>")
	)
	(segment
		(start 337.900264 -38.184074)
		(end 337.605878 -37.741606)
		(width 0.0889)
		(layer "F.Cu")
		(net "JTAG_TRC_PCH_PTI<13>")
	)
	(segment
		(start 345.105482 -14.000226)
		(end 359.540302 -14.000226)
		(width 0.12954)
		(layer "F.Cu")
		(net "JTAG_TRC_PCH_PTI<13>")
	)
	(segment
		(start 386.950458 -44.484798)
		(end 386.950458 -44.863258)
		(width 0.12954)
		(layer "F.Cu")
		(net "JTAG_TRC_PCH_PTI<13>")
	)
	(segment
		(start 387.484874 -53.24983)
		(end 387.857492 -53.24983)
		(width 0.12954)
		(layer "F.Cu")
		(net "JTAG_TRC_PCH_PTI<13>")
	)
	(segment
		(start 387.079998 -42.442638)
		(end 387.74878 -42.442638)
		(width 0.12954)
		(layer "F.Cu")
		(net "JTAG_TRC_PCH_PTI<13>")
	)
	(segment
		(start 359.540302 -14.000226)
		(end 386.950458 -41.410382)
		(width 0.12954)
		(layer "F.Cu")
		(net "JTAG_TRC_PCH_PTI<13>")
	)
	(segment
		(start 386.950458 -46.138338)
		(end 387.079998 -46.267878)
		(width 0.12954)
		(layer "F.Cu")
		(net "JTAG_TRC_PCH_PTI<13>")
	)
	(segment
		(start 338.051394 -29.729176)
		(end 338.949792 -28.830778)
		(width 0.12954)
		(layer "F.Cu")
		(net "JTAG_TRC_PCH_PTI<13>")
	)
	(segment
		(start 387.87832 -43.847258)
		(end 387.87832 -44.225718)
		(width 0.12954)
		(layer "F.Cu")
		(net "JTAG_TRC_PCH_PTI<13>")
	)
	(segment
		(start 387.74878 -44.992798)
		(end 387.87832 -45.122338)
		(width 0.12954)
		(layer "F.Cu")
		(net "JTAG_TRC_PCH_PTI<13>")
	)
	(segment
		(start 337.605878 -36.24199)
		(end 337.43646 -36.072572)
		(width 0.0889)
		(layer "F.Cu")
		(net "JTAG_TRC_PCH_PTI<13>")
	)
	(segment
		(start 386.950458 -44.863258)
		(end 387.079998 -44.992798)
		(width 0.12954)
		(layer "F.Cu")
		(net "JTAG_TRC_PCH_PTI<13>")
	)
	(segment
		(start 387.74878 -44.355258)
		(end 387.079998 -44.355258)
		(width 0.12954)
		(layer "F.Cu")
		(net "JTAG_TRC_PCH_PTI<13>")
	)
	(segment
		(start 387.079998 -44.355258)
		(end 386.950458 -44.484798)
		(width 0.12954)
		(layer "F.Cu")
		(net "JTAG_TRC_PCH_PTI<13>")
	)
	(segment
		(start 387.857492 -53.24983)
		(end 392.034776 -53.24983)
		(width 0.12954)
		(layer "F.Cu")
		(net "JTAG_TRC_PCH_PTI<13>")
	)
	(segment
		(start 387.74878 -43.717718)
		(end 387.87832 -43.847258)
		(width 0.12954)
		(layer "F.Cu")
		(net "JTAG_TRC_PCH_PTI<13>")
	)
	(segment
		(start 386.950458 -43.209718)
		(end 386.950458 -43.588178)
		(width 0.12954)
		(layer "F.Cu")
		(net "JTAG_TRC_PCH_PTI<13>")
	)
	(via
		(at 387.857492 -53.24983)
		(size 0.508)
		(drill 0.254)
		(layers "F.Cu" "B.Cu")
		(net "JTAG_TRC_PCH_PTI<13>")
	)
	(segment
		(start 383.27076 -47.834042)
		(end 383.27076 -52.18049)
		(width 0.12954)
		(layer "F.Cu")
		(net "JTAG_TRC_PCH_PTI<12>")
	)
	(segment
		(start 384.450336 -44.853352)
		(end 384.450336 -45.231812)
		(width 0.12954)
		(layer "F.Cu")
		(net "JTAG_TRC_PCH_PTI<12>")
	)
	(segment
		(start 384.944112 -45.998892)
		(end 384.579876 -45.998892)
		(width 0.12954)
		(layer "F.Cu")
		(net "JTAG_TRC_PCH_PTI<12>")
	)
	(segment
		(start 384.320796 -41.302432)
		(end 383.333498 -41.302432)
		(width 0.12954)
		(layer "F.Cu")
		(net "JTAG_TRC_PCH_PTI<12>")
	)
	(segment
		(start 340.373462 -28.204668)
		(end 340.373462 -19.74596)
		(width 0.12954)
		(layer "F.Cu")
		(net "JTAG_TRC_PCH_PTI<12>")
	)
	(segment
		(start 340.373462 -19.74596)
		(end 345.306904 -14.812518)
		(width 0.12954)
		(layer "F.Cu")
		(net "JTAG_TRC_PCH_PTI<12>")
	)
	(segment
		(start 385.200652 -53.339746)
		(end 385.38404 -53.339746)
		(width 0.12954)
		(layer "F.Cu")
		(net "JTAG_TRC_PCH_PTI<12>")
	)
	(segment
		(start 339.060282 -32.763968)
		(end 339.060282 -30.246828)
		(width 0.0889)
		(layer "F.Cu")
		(net "JTAG_TRC_PCH_PTI<12>")
	)
	(segment
		(start 383.82194 -52.73167)
		(end 384.005328 -52.73167)
		(width 0.12954)
		(layer "F.Cu")
		(net "JTAG_TRC_PCH_PTI<12>")
	)
	(segment
		(start 383.333498 -42.577512)
		(end 383.203958 -42.707052)
		(width 0.12954)
		(layer "F.Cu")
		(net "JTAG_TRC_PCH_PTI<12>")
	)
	(segment
		(start 384.944112 -45.361352)
		(end 385.073652 -45.490892)
		(width 0.12954)
		(layer "F.Cu")
		(net "JTAG_TRC_PCH_PTI<12>")
	)
	(segment
		(start 338.401152 -36.002468)
		(end 338.007198 -35.608514)
		(width 0.0889)
		(layer "F.Cu")
		(net "JTAG_TRC_PCH_PTI<12>")
	)
	(segment
		(start 392.034776 -53.749956)
		(end 389.419592 -53.749956)
		(width 0.12954)
		(layer "F.Cu")
		(net "JTAG_TRC_PCH_PTI<12>")
	)
	(segment
		(start 384.48234 -52.438046)
		(end 384.749802 -52.705508)
		(width 0.12954)
		(layer "F.Cu")
		(net "JTAG_TRC_PCH_PTI<12>")
	)
	(segment
		(start 338.007198 -33.817052)
		(end 339.060282 -32.763968)
		(width 0.0889)
		(layer "F.Cu")
		(net "JTAG_TRC_PCH_PTI<12>")
	)
	(segment
		(start 383.203958 -41.810432)
		(end 383.333498 -41.939972)
		(width 0.12954)
		(layer "F.Cu")
		(net "JTAG_TRC_PCH_PTI<12>")
	)
	(segment
		(start 384.320796 -41.939972)
		(end 384.450336 -42.069512)
		(width 0.12954)
		(layer "F.Cu")
		(net "JTAG_TRC_PCH_PTI<12>")
	)
	(segment
		(start 384.450336 -46.128432)
		(end 384.450336 -46.654466)
		(width 0.12954)
		(layer "F.Cu")
		(net "JTAG_TRC_PCH_PTI<12>")
	)
	(segment
		(start 384.320796 -42.577512)
		(end 383.333498 -42.577512)
		(width 0.12954)
		(layer "F.Cu")
		(net "JTAG_TRC_PCH_PTI<12>")
	)
	(segment
		(start 338.40039 -37.808154)
		(end 338.401152 -37.807392)
		(width 0.0889)
		(layer "F.Cu")
		(net "JTAG_TRC_PCH_PTI<12>")
	)
	(segment
		(start 384.005328 -52.73167)
		(end 384.298952 -52.438046)
		(width 0.12954)
		(layer "F.Cu")
		(net "JTAG_TRC_PCH_PTI<12>")
	)
	(segment
		(start 385.073652 -45.869352)
		(end 384.944112 -45.998892)
		(width 0.12954)
		(layer "F.Cu")
		(net "JTAG_TRC_PCH_PTI<12>")
	)
	(segment
		(start 384.450336 -41.172892)
		(end 384.320796 -41.302432)
		(width 0.12954)
		(layer "F.Cu")
		(net "JTAG_TRC_PCH_PTI<12>")
	)
	(segment
		(start 338.401152 -37.807392)
		(end 338.401152 -36.002468)
		(width 0.0889)
		(layer "F.Cu")
		(net "JTAG_TRC_PCH_PTI<12>")
	)
	(segment
		(start 384.72364 -53.63337)
		(end 384.907028 -53.63337)
		(width 0.12954)
		(layer "F.Cu")
		(net "JTAG_TRC_PCH_PTI<12>")
	)
	(segment
		(start 338.40039 -38.050216)
		(end 338.40039 -37.808154)
		(width 0.0889)
		(layer "F.Cu")
		(net "JTAG_TRC_PCH_PTI<12>")
	)
	(segment
		(start 385.651502 -53.790596)
		(end 385.357878 -54.08422)
		(width 0.12954)
		(layer "F.Cu")
		(net "JTAG_TRC_PCH_PTI<12>")
	)
	(segment
		(start 384.456178 -53.365908)
		(end 384.72364 -53.63337)
		(width 0.12954)
		(layer "F.Cu")
		(net "JTAG_TRC_PCH_PTI<12>")
	)
	(segment
		(start 338.007198 -35.608514)
		(end 338.007198 -33.817052)
		(width 0.0889)
		(layer "F.Cu")
		(net "JTAG_TRC_PCH_PTI<12>")
	)
	(segment
		(start 384.749802 -52.888896)
		(end 384.456178 -53.18252)
		(width 0.12954)
		(layer "F.Cu")
		(net "JTAG_TRC_PCH_PTI<12>")
	)
	(segment
		(start 384.907028 -53.63337)
		(end 385.200652 -53.339746)
		(width 0.12954)
		(layer "F.Cu")
		(net "JTAG_TRC_PCH_PTI<12>")
	)
	(segment
		(start 383.203958 -43.085512)
		(end 383.333498 -43.215052)
		(width 0.12954)
		(layer "F.Cu")
		(net "JTAG_TRC_PCH_PTI<12>")
	)
	(segment
		(start 384.450336 -43.344592)
		(end 384.450336 -43.956732)
		(width 0.12954)
		(layer "F.Cu")
		(net "JTAG_TRC_PCH_PTI<12>")
	)
	(segment
		(start 385.651502 -53.607208)
		(end 385.651502 -53.790596)
		(width 0.12954)
		(layer "F.Cu")
		(net "JTAG_TRC_PCH_PTI<12>")
	)
	(segment
		(start 385.073652 -44.594272)
		(end 384.944112 -44.723812)
		(width 0.12954)
		(layer "F.Cu")
		(net "JTAG_TRC_PCH_PTI<12>")
	)
	(segment
		(start 384.450336 -45.231812)
		(end 384.579876 -45.361352)
		(width 0.12954)
		(layer "F.Cu")
		(net "JTAG_TRC_PCH_PTI<12>")
	)
	(segment
		(start 384.944112 -44.723812)
		(end 384.579876 -44.723812)
		(width 0.12954)
		(layer "F.Cu")
		(net "JTAG_TRC_PCH_PTI<12>")
	)
	(segment
		(start 384.579876 -44.723812)
		(end 384.450336 -44.853352)
		(width 0.12954)
		(layer "F.Cu")
		(net "JTAG_TRC_PCH_PTI<12>")
	)
	(segment
		(start 339.060282 -30.246828)
		(end 340.333838 -28.973272)
		(width 0.12954)
		(layer "F.Cu")
		(net "JTAG_TRC_PCH_PTI<12>")
	)
	(segment
		(start 384.320796 -43.215052)
		(end 384.450336 -43.344592)
		(width 0.12954)
		(layer "F.Cu")
		(net "JTAG_TRC_PCH_PTI<12>")
	)
	(segment
		(start 340.333838 -28.973272)
		(end 340.333838 -28.300426)
		(width 0.12954)
		(layer "F.Cu")
		(net "JTAG_TRC_PCH_PTI<12>")
	)
	(segment
		(start 383.333498 -41.302432)
		(end 383.203958 -41.431972)
		(width 0.12954)
		(layer "F.Cu")
		(net "JTAG_TRC_PCH_PTI<12>")
	)
	(segment
		(start 383.333498 -43.215052)
		(end 384.320796 -43.215052)
		(width 0.12954)
		(layer "F.Cu")
		(net "JTAG_TRC_PCH_PTI<12>")
	)
	(segment
		(start 385.59994 -54.50967)
		(end 385.59994 -54.749954)
		(width 0.12954)
		(layer "F.Cu")
		(net "JTAG_TRC_PCH_PTI<12>")
	)
	(segment
		(start 385.073652 -45.490892)
		(end 385.073652 -45.869352)
		(width 0.12954)
		(layer "F.Cu")
		(net "JTAG_TRC_PCH_PTI<12>")
	)
	(segment
		(start 340.333838 -28.300426)
		(end 340.373462 -28.204668)
		(width 0.12954)
		(layer "F.Cu")
		(net "JTAG_TRC_PCH_PTI<12>")
	)
	(segment
		(start 384.298952 -52.438046)
		(end 384.48234 -52.438046)
		(width 0.12954)
		(layer "F.Cu")
		(net "JTAG_TRC_PCH_PTI<12>")
	)
	(segment
		(start 383.203958 -41.431972)
		(end 383.203958 -41.810432)
		(width 0.12954)
		(layer "F.Cu")
		(net "JTAG_TRC_PCH_PTI<12>")
	)
	(segment
		(start 385.357878 -54.267608)
		(end 385.59994 -54.50967)
		(width 0.12954)
		(layer "F.Cu")
		(net "JTAG_TRC_PCH_PTI<12>")
	)
	(segment
		(start 384.944112 -44.086272)
		(end 385.073652 -44.215812)
		(width 0.12954)
		(layer "F.Cu")
		(net "JTAG_TRC_PCH_PTI<12>")
	)
	(segment
		(start 384.450336 -46.654466)
		(end 383.27076 -47.834042)
		(width 0.12954)
		(layer "F.Cu")
		(net "JTAG_TRC_PCH_PTI<12>")
	)
	(segment
		(start 384.456178 -53.18252)
		(end 384.456178 -53.365908)
		(width 0.12954)
		(layer "F.Cu")
		(net "JTAG_TRC_PCH_PTI<12>")
	)
	(segment
		(start 383.203958 -42.707052)
		(end 383.203958 -43.085512)
		(width 0.12954)
		(layer "F.Cu")
		(net "JTAG_TRC_PCH_PTI<12>")
	)
	(segment
		(start 383.27076 -52.18049)
		(end 383.82194 -52.73167)
		(width 0.12954)
		(layer "F.Cu")
		(net "JTAG_TRC_PCH_PTI<12>")
	)
	(segment
		(start 384.579876 -44.086272)
		(end 384.944112 -44.086272)
		(width 0.12954)
		(layer "F.Cu")
		(net "JTAG_TRC_PCH_PTI<12>")
	)
	(segment
		(start 384.450336 -42.447972)
		(end 384.320796 -42.577512)
		(width 0.12954)
		(layer "F.Cu")
		(net "JTAG_TRC_PCH_PTI<12>")
	)
	(segment
		(start 384.450336 -43.956732)
		(end 384.579876 -44.086272)
		(width 0.12954)
		(layer "F.Cu")
		(net "JTAG_TRC_PCH_PTI<12>")
	)
	(segment
		(start 384.579876 -45.361352)
		(end 384.944112 -45.361352)
		(width 0.12954)
		(layer "F.Cu")
		(net "JTAG_TRC_PCH_PTI<12>")
	)
	(segment
		(start 383.333498 -41.939972)
		(end 384.320796 -41.939972)
		(width 0.12954)
		(layer "F.Cu")
		(net "JTAG_TRC_PCH_PTI<12>")
	)
	(segment
		(start 385.073652 -44.215812)
		(end 385.073652 -44.594272)
		(width 0.12954)
		(layer "F.Cu")
		(net "JTAG_TRC_PCH_PTI<12>")
	)
	(segment
		(start 385.357878 -54.08422)
		(end 385.357878 -54.267608)
		(width 0.12954)
		(layer "F.Cu")
		(net "JTAG_TRC_PCH_PTI<12>")
	)
	(segment
		(start 359.203752 -14.812518)
		(end 384.450336 -40.059102)
		(width 0.12954)
		(layer "F.Cu")
		(net "JTAG_TRC_PCH_PTI<12>")
	)
	(segment
		(start 384.749802 -52.705508)
		(end 384.749802 -52.888896)
		(width 0.12954)
		(layer "F.Cu")
		(net "JTAG_TRC_PCH_PTI<12>")
	)
	(segment
		(start 345.306904 -14.812518)
		(end 359.203752 -14.812518)
		(width 0.12954)
		(layer "F.Cu")
		(net "JTAG_TRC_PCH_PTI<12>")
	)
	(segment
		(start 384.450336 -40.059102)
		(end 384.450336 -41.172892)
		(width 0.12954)
		(layer "F.Cu")
		(net "JTAG_TRC_PCH_PTI<12>")
	)
	(segment
		(start 384.450336 -42.069512)
		(end 384.450336 -42.447972)
		(width 0.12954)
		(layer "F.Cu")
		(net "JTAG_TRC_PCH_PTI<12>")
	)
	(segment
		(start 385.38404 -53.339746)
		(end 385.651502 -53.607208)
		(width 0.12954)
		(layer "F.Cu")
		(net "JTAG_TRC_PCH_PTI<12>")
	)
	(segment
		(start 384.579876 -45.998892)
		(end 384.450336 -46.128432)
		(width 0.12954)
		(layer "F.Cu")
		(net "JTAG_TRC_PCH_PTI<12>")
	)
	(via
		(at 389.419592 -53.749956)
		(size 0.508)
		(drill 0.254)
		(layers "F.Cu" "B.Cu")
		(net "JTAG_TRC_PCH_PTI<12>")
	)
	(via
		(at 385.59994 -54.749954)
		(size 0.508)
		(drill 0.254)
		(layers "F.Cu" "B.Cu")
		(net "JTAG_TRC_PCH_PTI<12>")
	)
	(segment
		(start 387.647688 -54.103016)
		(end 387.046724 -54.103016)
		(width 0.12954)
		(layer "B.Cu")
		(net "JTAG_TRC_PCH_PTI<12>")
	)
	(segment
		(start 385.81965 -54.266338)
		(end 385.59994 -54.486048)
		(width 0.12954)
		(layer "B.Cu")
		(net "JTAG_TRC_PCH_PTI<12>")
	)
	(segment
		(start 389.419592 -53.749956)
		(end 388.66318 -54.506368)
		(width 0.12954)
		(layer "B.Cu")
		(net "JTAG_TRC_PCH_PTI<12>")
	)
	(segment
		(start 388.05104 -54.506368)
		(end 387.647688 -54.103016)
		(width 0.12954)
		(layer "B.Cu")
		(net "JTAG_TRC_PCH_PTI<12>")
	)
	(segment
		(start 387.046724 -54.103016)
		(end 386.883402 -54.266338)
		(width 0.12954)
		(layer "B.Cu")
		(net "JTAG_TRC_PCH_PTI<12>")
	)
	(segment
		(start 386.883402 -54.266338)
		(end 385.81965 -54.266338)
		(width 0.12954)
		(layer "B.Cu")
		(net "JTAG_TRC_PCH_PTI<12>")
	)
	(segment
		(start 388.66318 -54.506368)
		(end 388.05104 -54.506368)
		(width 0.12954)
		(layer "B.Cu")
		(net "JTAG_TRC_PCH_PTI<12>")
	)
	(segment
		(start 385.59994 -54.486048)
		(end 385.59994 -54.749954)
		(width 0.12954)
		(layer "B.Cu")
		(net "JTAG_TRC_PCH_PTI<12>")
	)
	(segment
		(start 385.761992 -46.353476)
		(end 385.632452 -46.483016)
		(width 0.12954)
		(layer "F.Cu")
		(net "JTAG_TRC_PCH_PTI<11>")
	)
	(segment
		(start 385.760976 -52.049172)
		(end 386.028438 -52.316634)
		(width 0.12954)
		(layer "F.Cu")
		(net "JTAG_TRC_PCH_PTI<11>")
	)
	(segment
		(start 386.710428 -54.249828)
		(end 392.034776 -54.249828)
		(width 0.12954)
		(layer "F.Cu")
		(net "JTAG_TRC_PCH_PTI<11>")
	)
	(segment
		(start 339.991192 -28.085034)
		(end 339.991192 -19.621246)
		(width 0.12954)
		(layer "F.Cu")
		(net "JTAG_TRC_PCH_PTI<11>")
	)
	(segment
		(start 385.761992 -45.715936)
		(end 386.223002 -45.715936)
		(width 0.12954)
		(layer "F.Cu")
		(net "JTAG_TRC_PCH_PTI<11>")
	)
	(segment
		(start 338.14639 -36.118038)
		(end 337.816952 -35.7886)
		(width 0.0889)
		(layer "F.Cu")
		(net "JTAG_TRC_PCH_PTI<11>")
	)
	(segment
		(start 385.761992 -44.440856)
		(end 386.223002 -44.440856)
		(width 0.12954)
		(layer "F.Cu")
		(net "JTAG_TRC_PCH_PTI<11>")
	)
	(segment
		(start 385.63169 -53.080158)
		(end 386.101082 -53.54955)
		(width 0.12954)
		(layer "F.Cu")
		(net "JTAG_TRC_PCH_PTI<11>")
	)
	(segment
		(start 383.65176 -51.100228)
		(end 384.095752 -51.54422)
		(width 0.12954)
		(layer "F.Cu")
		(net "JTAG_TRC_PCH_PTI<11>")
	)
	(segment
		(start 385.502912 -43.598592)
		(end 385.632452 -43.728132)
		(width 0.12954)
		(layer "F.Cu")
		(net "JTAG_TRC_PCH_PTI<11>")
	)
	(segment
		(start 385.632452 -42.831512)
		(end 385.502912 -42.961052)
		(width 0.12954)
		(layer "F.Cu")
		(net "JTAG_TRC_PCH_PTI<11>")
	)
	(segment
		(start 385.502912 -42.323512)
		(end 385.632452 -42.453052)
		(width 0.12954)
		(layer "F.Cu")
		(net "JTAG_TRC_PCH_PTI<11>")
	)
	(segment
		(start 339.952076 -28.179522)
		(end 339.991192 -28.085034)
		(width 0.12954)
		(layer "F.Cu")
		(net "JTAG_TRC_PCH_PTI<11>")
	)
	(segment
		(start 385.502912 -41.685972)
		(end 385.07416 -41.685972)
		(width 0.12954)
		(layer "F.Cu")
		(net "JTAG_TRC_PCH_PTI<11>")
	)
	(segment
		(start 385.63169 -52.89677)
		(end 385.63169 -53.080158)
		(width 0.12954)
		(layer "F.Cu")
		(net "JTAG_TRC_PCH_PTI<11>")
	)
	(segment
		(start 337.816952 -33.659318)
		(end 338.780882 -32.695388)
		(width 0.0889)
		(layer "F.Cu")
		(net "JTAG_TRC_PCH_PTI<11>")
	)
	(segment
		(start 386.352542 -44.948856)
		(end 386.223002 -45.078396)
		(width 0.12954)
		(layer "F.Cu")
		(net "JTAG_TRC_PCH_PTI<11>")
	)
	(segment
		(start 385.632452 -47.095156)
		(end 385.42849 -47.299118)
		(width 0.12954)
		(layer "F.Cu")
		(net "JTAG_TRC_PCH_PTI<11>")
	)
	(segment
		(start 338.780882 -30.015942)
		(end 339.952076 -28.844748)
		(width 0.12954)
		(layer "F.Cu")
		(net "JTAG_TRC_PCH_PTI<11>")
	)
	(segment
		(start 338.098892 -38.196012)
		(end 338.098892 -37.903912)
		(width 0.0889)
		(layer "F.Cu")
		(net "JTAG_TRC_PCH_PTI<11>")
	)
	(segment
		(start 338.184744 -37.407596)
		(end 338.14639 -37.213286)
		(width 0.0889)
		(layer "F.Cu")
		(net "JTAG_TRC_PCH_PTI<11>")
	)
	(segment
		(start 385.632452 -41.556432)
		(end 385.502912 -41.685972)
		(width 0.12954)
		(layer "F.Cu")
		(net "JTAG_TRC_PCH_PTI<11>")
	)
	(segment
		(start 386.223002 -45.078396)
		(end 385.761992 -45.078396)
		(width 0.12954)
		(layer "F.Cu")
		(net "JTAG_TRC_PCH_PTI<11>")
	)
	(segment
		(start 385.761992 -45.078396)
		(end 385.632452 -45.207936)
		(width 0.12954)
		(layer "F.Cu")
		(net "JTAG_TRC_PCH_PTI<11>")
	)
	(segment
		(start 386.590286 -54.129686)
		(end 386.710428 -54.249828)
		(width 0.12954)
		(layer "F.Cu")
		(net "JTAG_TRC_PCH_PTI<11>")
	)
	(segment
		(start 384.94462 -42.193972)
		(end 385.07416 -42.323512)
		(width 0.12954)
		(layer "F.Cu")
		(net "JTAG_TRC_PCH_PTI<11>")
	)
	(segment
		(start 338.14639 -37.213286)
		(end 338.14639 -36.118038)
		(width 0.0889)
		(layer "F.Cu")
		(net "JTAG_TRC_PCH_PTI<11>")
	)
	(segment
		(start 384.94462 -43.469052)
		(end 385.07416 -43.598592)
		(width 0.12954)
		(layer "F.Cu")
		(net "JTAG_TRC_PCH_PTI<11>")
	)
	(segment
		(start 384.94462 -43.090592)
		(end 384.94462 -43.469052)
		(width 0.12954)
		(layer "F.Cu")
		(net "JTAG_TRC_PCH_PTI<11>")
	)
	(segment
		(start 385.126738 -51.598322)
		(end 384.72999 -51.99507)
		(width 0.12954)
		(layer "F.Cu")
		(net "JTAG_TRC_PCH_PTI<11>")
	)
	(segment
		(start 385.632452 -43.728132)
		(end 385.632452 -44.311316)
		(width 0.12954)
		(layer "F.Cu")
		(net "JTAG_TRC_PCH_PTI<11>")
	)
	(segment
		(start 338.098892 -37.903912)
		(end 338.145374 -37.833808)
		(width 0.0889)
		(layer "F.Cu")
		(net "JTAG_TRC_PCH_PTI<11>")
	)
	(segment
		(start 386.352542 -45.845476)
		(end 386.352542 -46.223936)
		(width 0.12954)
		(layer "F.Cu")
		(net "JTAG_TRC_PCH_PTI<11>")
	)
	(segment
		(start 339.952076 -28.844748)
		(end 339.952076 -28.179522)
		(width 0.12954)
		(layer "F.Cu")
		(net "JTAG_TRC_PCH_PTI<11>")
	)
	(segment
		(start 383.65176 -48.226726)
		(end 383.65176 -51.100228)
		(width 0.12954)
		(layer "F.Cu")
		(net "JTAG_TRC_PCH_PTI<11>")
	)
	(segment
		(start 338.780882 -32.695388)
		(end 338.780882 -30.015942)
		(width 0.0889)
		(layer "F.Cu")
		(net "JTAG_TRC_PCH_PTI<11>")
	)
	(segment
		(start 384.27914 -51.54422)
		(end 384.675888 -51.147472)
		(width 0.12954)
		(layer "F.Cu")
		(net "JTAG_TRC_PCH_PTI<11>")
	)
	(segment
		(start 385.632452 -40.723566)
		(end 385.632452 -41.556432)
		(width 0.12954)
		(layer "F.Cu")
		(net "JTAG_TRC_PCH_PTI<11>")
	)
	(segment
		(start 339.991192 -19.621246)
		(end 345.165934 -14.446504)
		(width 0.12954)
		(layer "F.Cu")
		(net "JTAG_TRC_PCH_PTI<11>")
	)
	(segment
		(start 338.228178 -38.345618)
		(end 338.098892 -38.196012)
		(width 0.0889)
		(layer "F.Cu")
		(net "JTAG_TRC_PCH_PTI<11>")
	)
	(segment
		(start 385.07416 -43.598592)
		(end 385.502912 -43.598592)
		(width 0.12954)
		(layer "F.Cu")
		(net "JTAG_TRC_PCH_PTI<11>")
	)
	(segment
		(start 385.632452 -46.483016)
		(end 385.632452 -47.095156)
		(width 0.12954)
		(layer "F.Cu")
		(net "JTAG_TRC_PCH_PTI<11>")
	)
	(segment
		(start 385.502912 -42.961052)
		(end 385.07416 -42.961052)
		(width 0.12954)
		(layer "F.Cu")
		(net "JTAG_TRC_PCH_PTI<11>")
	)
	(segment
		(start 385.42849 -47.299118)
		(end 384.579368 -47.299118)
		(width 0.12954)
		(layer "F.Cu")
		(net "JTAG_TRC_PCH_PTI<11>")
	)
	(segment
		(start 386.223002 -46.353476)
		(end 385.761992 -46.353476)
		(width 0.12954)
		(layer "F.Cu")
		(net "JTAG_TRC_PCH_PTI<11>")
	)
	(segment
		(start 384.72999 -51.99507)
		(end 384.72999 -52.178458)
		(width 0.12954)
		(layer "F.Cu")
		(net "JTAG_TRC_PCH_PTI<11>")
	)
	(segment
		(start 338.40039 -38.880288)
		(end 338.400644 -38.880034)
		(width 0.0889)
		(layer "F.Cu")
		(net "JTAG_TRC_PCH_PTI<11>")
	)
	(segment
		(start 384.095752 -51.54422)
		(end 384.27914 -51.54422)
		(width 0.12954)
		(layer "F.Cu")
		(net "JTAG_TRC_PCH_PTI<11>")
	)
	(segment
		(start 386.223002 -45.715936)
		(end 386.352542 -45.845476)
		(width 0.12954)
		(layer "F.Cu")
		(net "JTAG_TRC_PCH_PTI<11>")
	)
	(segment
		(start 385.632452 -42.453052)
		(end 385.632452 -42.831512)
		(width 0.12954)
		(layer "F.Cu")
		(net "JTAG_TRC_PCH_PTI<11>")
	)
	(segment
		(start 338.400644 -38.518084)
		(end 338.228178 -38.345618)
		(width 0.0889)
		(layer "F.Cu")
		(net "JTAG_TRC_PCH_PTI<11>")
	)
	(segment
		(start 385.07416 -42.323512)
		(end 385.502912 -42.323512)
		(width 0.12954)
		(layer "F.Cu")
		(net "JTAG_TRC_PCH_PTI<11>")
	)
	(segment
		(start 384.72999 -52.178458)
		(end 384.997452 -52.44592)
		(width 0.12954)
		(layer "F.Cu")
		(net "JTAG_TRC_PCH_PTI<11>")
	)
	(segment
		(start 385.126738 -51.414934)
		(end 385.126738 -51.598322)
		(width 0.12954)
		(layer "F.Cu")
		(net "JTAG_TRC_PCH_PTI<11>")
	)
	(segment
		(start 386.028438 -52.500022)
		(end 385.63169 -52.89677)
		(width 0.12954)
		(layer "F.Cu")
		(net "JTAG_TRC_PCH_PTI<11>")
	)
	(segment
		(start 384.675888 -51.147472)
		(end 384.859276 -51.147472)
		(width 0.12954)
		(layer "F.Cu")
		(net "JTAG_TRC_PCH_PTI<11>")
	)
	(segment
		(start 385.632452 -44.311316)
		(end 385.761992 -44.440856)
		(width 0.12954)
		(layer "F.Cu")
		(net "JTAG_TRC_PCH_PTI<11>")
	)
	(segment
		(start 386.223002 -44.440856)
		(end 386.352542 -44.570396)
		(width 0.12954)
		(layer "F.Cu")
		(net "JTAG_TRC_PCH_PTI<11>")
	)
	(segment
		(start 345.165934 -14.446504)
		(end 359.35539 -14.446504)
		(width 0.12954)
		(layer "F.Cu")
		(net "JTAG_TRC_PCH_PTI<11>")
	)
	(segment
		(start 384.579368 -47.299118)
		(end 383.65176 -48.226726)
		(width 0.12954)
		(layer "F.Cu")
		(net "JTAG_TRC_PCH_PTI<11>")
	)
	(segment
		(start 338.184744 -37.794438)
		(end 338.184744 -37.407596)
		(width 0.0889)
		(layer "F.Cu")
		(net "JTAG_TRC_PCH_PTI<11>")
	)
	(segment
		(start 385.632452 -45.207936)
		(end 385.632452 -45.586396)
		(width 0.12954)
		(layer "F.Cu")
		(net "JTAG_TRC_PCH_PTI<11>")
	)
	(segment
		(start 385.07416 -42.961052)
		(end 384.94462 -43.090592)
		(width 0.12954)
		(layer "F.Cu")
		(net "JTAG_TRC_PCH_PTI<11>")
	)
	(segment
		(start 384.859276 -51.147472)
		(end 385.126738 -51.414934)
		(width 0.12954)
		(layer "F.Cu")
		(net "JTAG_TRC_PCH_PTI<11>")
	)
	(segment
		(start 385.632452 -45.586396)
		(end 385.761992 -45.715936)
		(width 0.12954)
		(layer "F.Cu")
		(net "JTAG_TRC_PCH_PTI<11>")
	)
	(segment
		(start 385.07416 -41.685972)
		(end 384.94462 -41.815512)
		(width 0.12954)
		(layer "F.Cu")
		(net "JTAG_TRC_PCH_PTI<11>")
	)
	(segment
		(start 386.352542 -46.223936)
		(end 386.223002 -46.353476)
		(width 0.12954)
		(layer "F.Cu")
		(net "JTAG_TRC_PCH_PTI<11>")
	)
	(segment
		(start 338.145374 -37.833808)
		(end 338.184744 -37.794438)
		(width 0.0889)
		(layer "F.Cu")
		(net "JTAG_TRC_PCH_PTI<11>")
	)
	(segment
		(start 338.400644 -38.880034)
		(end 338.400644 -38.518084)
		(width 0.0889)
		(layer "F.Cu")
		(net "JTAG_TRC_PCH_PTI<11>")
	)
	(segment
		(start 384.94462 -41.815512)
		(end 384.94462 -42.193972)
		(width 0.12954)
		(layer "F.Cu")
		(net "JTAG_TRC_PCH_PTI<11>")
	)
	(segment
		(start 384.997452 -52.44592)
		(end 385.18084 -52.44592)
		(width 0.12954)
		(layer "F.Cu")
		(net "JTAG_TRC_PCH_PTI<11>")
	)
	(segment
		(start 337.816952 -35.7886)
		(end 337.816952 -33.659318)
		(width 0.0889)
		(layer "F.Cu")
		(net "JTAG_TRC_PCH_PTI<11>")
	)
	(segment
		(start 386.352542 -44.570396)
		(end 386.352542 -44.948856)
		(width 0.12954)
		(layer "F.Cu")
		(net "JTAG_TRC_PCH_PTI<11>")
	)
	(segment
		(start 386.590286 -53.54955)
		(end 386.590286 -54.129686)
		(width 0.12954)
		(layer "F.Cu")
		(net "JTAG_TRC_PCH_PTI<11>")
	)
	(segment
		(start 385.18084 -52.44592)
		(end 385.577588 -52.049172)
		(width 0.12954)
		(layer "F.Cu")
		(net "JTAG_TRC_PCH_PTI<11>")
	)
	(segment
		(start 359.35539 -14.446504)
		(end 385.632452 -40.723566)
		(width 0.12954)
		(layer "F.Cu")
		(net "JTAG_TRC_PCH_PTI<11>")
	)
	(segment
		(start 386.028438 -52.316634)
		(end 386.028438 -52.500022)
		(width 0.12954)
		(layer "F.Cu")
		(net "JTAG_TRC_PCH_PTI<11>")
	)
	(segment
		(start 385.577588 -52.049172)
		(end 385.760976 -52.049172)
		(width 0.12954)
		(layer "F.Cu")
		(net "JTAG_TRC_PCH_PTI<11>")
	)
	(segment
		(start 386.101082 -53.54955)
		(end 386.590286 -53.54955)
		(width 0.12954)
		(layer "F.Cu")
		(net "JTAG_TRC_PCH_PTI<11>")
	)
	(via
		(at 386.590286 -53.54955)
		(size 0.508)
		(drill 0.254)
		(layers "F.Cu" "B.Cu")
		(net "JTAG_TRC_PCH_PTI<11>")
	)
	(segment
		(start 380.521464 -43.053)
		(end 380.521464 -43.43146)
		(width 0.12954)
		(layer "F.Cu")
		(net "JTAG_TRC_PCH_PTI<10>")
	)
	(segment
		(start 340.591648 -31.484316)
		(end 340.874604 -31.20136)
		(width 0.12954)
		(layer "F.Cu")
		(net "JTAG_TRC_PCH_PTI<10>")
	)
	(segment
		(start 380.651004 -41.01084)
		(end 380.906782 -41.01084)
		(width 0.12954)
		(layer "F.Cu")
		(net "JTAG_TRC_PCH_PTI<10>")
	)
	(segment
		(start 380.651004 -46.11116)
		(end 380.906782 -46.11116)
		(width 0.12954)
		(layer "F.Cu")
		(net "JTAG_TRC_PCH_PTI<10>")
	)
	(segment
		(start 339.400896 -38.050216)
		(end 339.400896 -37.832792)
		(width 0.0889)
		(layer "F.Cu")
		(net "JTAG_TRC_PCH_PTI<10>")
	)
	(segment
		(start 380.651004 -48.02378)
		(end 380.521464 -48.15332)
		(width 0.12954)
		(layer "F.Cu")
		(net "JTAG_TRC_PCH_PTI<10>")
	)
	(segment
		(start 380.521464 -39.60622)
		(end 380.651004 -39.73576)
		(width 0.12954)
		(layer "F.Cu")
		(net "JTAG_TRC_PCH_PTI<10>")
	)
	(segment
		(start 380.651004 -48.66132)
		(end 380.906782 -48.66132)
		(width 0.12954)
		(layer "F.Cu")
		(net "JTAG_TRC_PCH_PTI<10>")
	)
	(segment
		(start 380.906782 -41.64838)
		(end 380.651004 -41.64838)
		(width 0.12954)
		(layer "F.Cu")
		(net "JTAG_TRC_PCH_PTI<10>")
	)
	(segment
		(start 341.5538 -20.08632)
		(end 345.753182 -15.886938)
		(width 0.12954)
		(layer "F.Cu")
		(net "JTAG_TRC_PCH_PTI<10>")
	)
	(segment
		(start 381.036322 -46.61916)
		(end 380.906782 -46.7487)
		(width 0.12954)
		(layer "F.Cu")
		(net "JTAG_TRC_PCH_PTI<10>")
	)
	(segment
		(start 380.521464 -47.2567)
		(end 380.651004 -47.38624)
		(width 0.12954)
		(layer "F.Cu")
		(net "JTAG_TRC_PCH_PTI<10>")
	)
	(segment
		(start 380.651004 -43.561)
		(end 380.906782 -43.561)
		(width 0.12954)
		(layer "F.Cu")
		(net "JTAG_TRC_PCH_PTI<10>")
	)
	(segment
		(start 381.036322 -49.16932)
		(end 380.906782 -49.29886)
		(width 0.12954)
		(layer "F.Cu")
		(net "JTAG_TRC_PCH_PTI<10>")
	)
	(segment
		(start 340.874604 -30.56382)
		(end 341.767668 -29.670756)
		(width 0.12954)
		(layer "F.Cu")
		(net "JTAG_TRC_PCH_PTI<10>")
	)
	(segment
		(start 380.521464 -51.351942)
		(end 383.275586 -54.106064)
		(width 0.12954)
		(layer "F.Cu")
		(net "JTAG_TRC_PCH_PTI<10>")
	)
	(segment
		(start 380.521464 -40.8813)
		(end 380.651004 -41.01084)
		(width 0.12954)
		(layer "F.Cu")
		(net "JTAG_TRC_PCH_PTI<10>")
	)
	(segment
		(start 340.874604 -31.20136)
		(end 340.874604 -30.56382)
		(width 0.12954)
		(layer "F.Cu")
		(net "JTAG_TRC_PCH_PTI<10>")
	)
	(segment
		(start 381.036322 -47.89424)
		(end 380.906782 -48.02378)
		(width 0.12954)
		(layer "F.Cu")
		(net "JTAG_TRC_PCH_PTI<10>")
	)
	(segment
		(start 380.651004 -44.83608)
		(end 380.906782 -44.83608)
		(width 0.12954)
		(layer "F.Cu")
		(net "JTAG_TRC_PCH_PTI<10>")
	)
	(segment
		(start 340.591648 -32.805878)
		(end 340.591648 -31.773368)
		(width 0.0889)
		(layer "F.Cu")
		(net "JTAG_TRC_PCH_PTI<10>")
	)
	(segment
		(start 380.521464 -49.80686)
		(end 380.651004 -49.9364)
		(width 0.12954)
		(layer "F.Cu")
		(net "JTAG_TRC_PCH_PTI<10>")
	)
	(segment
		(start 380.906782 -45.47362)
		(end 380.651004 -45.47362)
		(width 0.12954)
		(layer "F.Cu")
		(net "JTAG_TRC_PCH_PTI<10>")
	)
	(segment
		(start 339.471 -33.926526)
		(end 340.591648 -32.805878)
		(width 0.0889)
		(layer "F.Cu")
		(net "JTAG_TRC_PCH_PTI<10>")
	)
	(segment
		(start 383.275586 -54.106064)
		(end 383.275586 -54.813708)
		(width 0.12954)
		(layer "F.Cu")
		(net "JTAG_TRC_PCH_PTI<10>")
	)
	(segment
		(start 380.651004 -46.7487)
		(end 380.521464 -46.87824)
		(width 0.12954)
		(layer "F.Cu")
		(net "JTAG_TRC_PCH_PTI<10>")
	)
	(segment
		(start 380.651004 -40.3733)
		(end 380.521464 -40.50284)
		(width 0.12954)
		(layer "F.Cu")
		(net "JTAG_TRC_PCH_PTI<10>")
	)
	(segment
		(start 380.906782 -44.19854)
		(end 380.651004 -44.19854)
		(width 0.12954)
		(layer "F.Cu")
		(net "JTAG_TRC_PCH_PTI<10>")
	)
	(segment
		(start 380.651004 -45.47362)
		(end 380.521464 -45.60316)
		(width 0.12954)
		(layer "F.Cu")
		(net "JTAG_TRC_PCH_PTI<10>")
	)
	(segment
		(start 381.036322 -42.41546)
		(end 381.036322 -42.79392)
		(width 0.12954)
		(layer "F.Cu")
		(net "JTAG_TRC_PCH_PTI<10>")
	)
	(segment
		(start 380.651004 -49.9364)
		(end 380.906782 -49.9364)
		(width 0.12954)
		(layer "F.Cu")
		(net "JTAG_TRC_PCH_PTI<10>")
	)
	(segment
		(start 380.906782 -46.7487)
		(end 380.651004 -46.7487)
		(width 0.12954)
		(layer "F.Cu")
		(net "JTAG_TRC_PCH_PTI<10>")
	)
	(segment
		(start 340.591648 -31.773368)
		(end 340.591648 -31.484316)
		(width 0.12954)
		(layer "F.Cu")
		(net "JTAG_TRC_PCH_PTI<10>")
	)
	(segment
		(start 380.906782 -48.66132)
		(end 381.036322 -48.79086)
		(width 0.12954)
		(layer "F.Cu")
		(net "JTAG_TRC_PCH_PTI<10>")
	)
	(segment
		(start 380.906782 -47.38624)
		(end 381.036322 -47.51578)
		(width 0.12954)
		(layer "F.Cu")
		(net "JTAG_TRC_PCH_PTI<10>")
	)
	(segment
		(start 380.521464 -44.70654)
		(end 380.651004 -44.83608)
		(width 0.12954)
		(layer "F.Cu")
		(net "JTAG_TRC_PCH_PTI<10>")
	)
	(segment
		(start 341.767668 -28.57627)
		(end 341.825072 -28.437586)
		(width 0.12954)
		(layer "F.Cu")
		(net "JTAG_TRC_PCH_PTI<10>")
	)
	(segment
		(start 380.521464 -45.60316)
		(end 380.521464 -45.98162)
		(width 0.12954)
		(layer "F.Cu")
		(net "JTAG_TRC_PCH_PTI<10>")
	)
	(segment
		(start 381.036322 -47.51578)
		(end 381.036322 -47.89424)
		(width 0.12954)
		(layer "F.Cu")
		(net "JTAG_TRC_PCH_PTI<10>")
	)
	(segment
		(start 381.036322 -44.96562)
		(end 381.036322 -45.34408)
		(width 0.12954)
		(layer "F.Cu")
		(net "JTAG_TRC_PCH_PTI<10>")
	)
	(segment
		(start 381.036322 -41.14038)
		(end 381.036322 -41.51884)
		(width 0.12954)
		(layer "F.Cu")
		(net "JTAG_TRC_PCH_PTI<10>")
	)
	(segment
		(start 380.651004 -44.19854)
		(end 380.521464 -44.32808)
		(width 0.12954)
		(layer "F.Cu")
		(net "JTAG_TRC_PCH_PTI<10>")
	)
	(segment
		(start 341.825072 -25.69083)
		(end 342.750648 -24.765254)
		(width 0.12954)
		(layer "F.Cu")
		(net "JTAG_TRC_PCH_PTI<10>")
	)
	(segment
		(start 342.750648 -22.873716)
		(end 341.5538 -21.676868)
		(width 0.12954)
		(layer "F.Cu")
		(net "JTAG_TRC_PCH_PTI<10>")
	)
	(segment
		(start 380.521464 -48.15332)
		(end 380.521464 -48.53178)
		(width 0.12954)
		(layer "F.Cu")
		(net "JTAG_TRC_PCH_PTI<10>")
	)
	(segment
		(start 380.521464 -44.32808)
		(end 380.521464 -44.70654)
		(width 0.12954)
		(layer "F.Cu")
		(net "JTAG_TRC_PCH_PTI<10>")
	)
	(segment
		(start 380.906782 -41.01084)
		(end 381.036322 -41.14038)
		(width 0.12954)
		(layer "F.Cu")
		(net "JTAG_TRC_PCH_PTI<10>")
	)
	(segment
		(start 380.906782 -42.92346)
		(end 380.651004 -42.92346)
		(width 0.12954)
		(layer "F.Cu")
		(net "JTAG_TRC_PCH_PTI<10>")
	)
	(segment
		(start 380.906782 -44.83608)
		(end 381.036322 -44.96562)
		(width 0.12954)
		(layer "F.Cu")
		(net "JTAG_TRC_PCH_PTI<10>")
	)
	(segment
		(start 342.750648 -24.765254)
		(end 342.750648 -22.873716)
		(width 0.12954)
		(layer "F.Cu")
		(net "JTAG_TRC_PCH_PTI<10>")
	)
	(segment
		(start 380.651004 -49.29886)
		(end 380.521464 -49.4284)
		(width 0.12954)
		(layer "F.Cu")
		(net "JTAG_TRC_PCH_PTI<10>")
	)
	(segment
		(start 380.651004 -42.28592)
		(end 380.906782 -42.28592)
		(width 0.12954)
		(layer "F.Cu")
		(net "JTAG_TRC_PCH_PTI<10>")
	)
	(segment
		(start 380.521464 -41.77792)
		(end 380.521464 -42.15638)
		(width 0.12954)
		(layer "F.Cu")
		(net "JTAG_TRC_PCH_PTI<10>")
	)
	(segment
		(start 381.036322 -50.06594)
		(end 381.036322 -50.4444)
		(width 0.12954)
		(layer "F.Cu")
		(net "JTAG_TRC_PCH_PTI<10>")
	)
	(segment
		(start 380.906782 -43.561)
		(end 381.036322 -43.69054)
		(width 0.12954)
		(layer "F.Cu")
		(net "JTAG_TRC_PCH_PTI<10>")
	)
	(segment
		(start 380.651004 -41.64838)
		(end 380.521464 -41.77792)
		(width 0.12954)
		(layer "F.Cu")
		(net "JTAG_TRC_PCH_PTI<10>")
	)
	(segment
		(start 380.521464 -48.53178)
		(end 380.651004 -48.66132)
		(width 0.12954)
		(layer "F.Cu")
		(net "JTAG_TRC_PCH_PTI<10>")
	)
	(segment
		(start 380.521464 -45.98162)
		(end 380.651004 -46.11116)
		(width 0.12954)
		(layer "F.Cu")
		(net "JTAG_TRC_PCH_PTI<10>")
	)
	(segment
		(start 380.651004 -39.73576)
		(end 380.906782 -39.73576)
		(width 0.12954)
		(layer "F.Cu")
		(net "JTAG_TRC_PCH_PTI<10>")
	)
	(segment
		(start 381.036322 -48.79086)
		(end 381.036322 -49.16932)
		(width 0.12954)
		(layer "F.Cu")
		(net "JTAG_TRC_PCH_PTI<10>")
	)
	(segment
		(start 380.651004 -50.57394)
		(end 380.521464 -50.70348)
		(width 0.12954)
		(layer "F.Cu")
		(net "JTAG_TRC_PCH_PTI<10>")
	)
	(segment
		(start 381.036322 -50.4444)
		(end 380.906782 -50.57394)
		(width 0.12954)
		(layer "F.Cu")
		(net "JTAG_TRC_PCH_PTI<10>")
	)
	(segment
		(start 380.651004 -42.92346)
		(end 380.521464 -43.053)
		(width 0.12954)
		(layer "F.Cu")
		(net "JTAG_TRC_PCH_PTI<10>")
	)
	(segment
		(start 380.521464 -40.50284)
		(end 380.521464 -40.8813)
		(width 0.12954)
		(layer "F.Cu")
		(net "JTAG_TRC_PCH_PTI<10>")
	)
	(segment
		(start 380.521464 -37.962332)
		(end 380.521464 -39.60622)
		(width 0.12954)
		(layer "F.Cu")
		(net "JTAG_TRC_PCH_PTI<10>")
	)
	(segment
		(start 339.400896 -37.832792)
		(end 339.40115 -37.832792)
		(width 0.0889)
		(layer "F.Cu")
		(net "JTAG_TRC_PCH_PTI<10>")
	)
	(segment
		(start 380.906782 -49.29886)
		(end 380.651004 -49.29886)
		(width 0.12954)
		(layer "F.Cu")
		(net "JTAG_TRC_PCH_PTI<10>")
	)
	(segment
		(start 381.036322 -44.069)
		(end 380.906782 -44.19854)
		(width 0.12954)
		(layer "F.Cu")
		(net "JTAG_TRC_PCH_PTI<10>")
	)
	(segment
		(start 381.036322 -39.8653)
		(end 381.036322 -40.24376)
		(width 0.12954)
		(layer "F.Cu")
		(net "JTAG_TRC_PCH_PTI<10>")
	)
	(segment
		(start 339.471 -36.88588)
		(end 339.471 -33.926526)
		(width 0.0889)
		(layer "F.Cu")
		(net "JTAG_TRC_PCH_PTI<10>")
	)
	(segment
		(start 339.40115 -37.832792)
		(end 339.40115 -36.95573)
		(width 0.0889)
		(layer "F.Cu")
		(net "JTAG_TRC_PCH_PTI<10>")
	)
	(segment
		(start 380.906782 -40.3733)
		(end 380.651004 -40.3733)
		(width 0.12954)
		(layer "F.Cu")
		(net "JTAG_TRC_PCH_PTI<10>")
	)
	(segment
		(start 381.036322 -41.51884)
		(end 380.906782 -41.64838)
		(width 0.12954)
		(layer "F.Cu")
		(net "JTAG_TRC_PCH_PTI<10>")
	)
	(segment
		(start 380.521464 -43.43146)
		(end 380.651004 -43.561)
		(width 0.12954)
		(layer "F.Cu")
		(net "JTAG_TRC_PCH_PTI<10>")
	)
	(segment
		(start 380.521464 -49.4284)
		(end 380.521464 -49.80686)
		(width 0.12954)
		(layer "F.Cu")
		(net "JTAG_TRC_PCH_PTI<10>")
	)
	(segment
		(start 380.906782 -42.28592)
		(end 381.036322 -42.41546)
		(width 0.12954)
		(layer "F.Cu")
		(net "JTAG_TRC_PCH_PTI<10>")
	)
	(segment
		(start 392.034776 -54.749954)
		(end 387.232906 -54.749954)
		(width 0.12954)
		(layer "F.Cu")
		(net "JTAG_TRC_PCH_PTI<10>")
	)
	(segment
		(start 380.906782 -49.9364)
		(end 381.036322 -50.06594)
		(width 0.12954)
		(layer "F.Cu")
		(net "JTAG_TRC_PCH_PTI<10>")
	)
	(segment
		(start 380.651004 -47.38624)
		(end 380.906782 -47.38624)
		(width 0.12954)
		(layer "F.Cu")
		(net "JTAG_TRC_PCH_PTI<10>")
	)
	(segment
		(start 380.906782 -46.11116)
		(end 381.036322 -46.2407)
		(width 0.12954)
		(layer "F.Cu")
		(net "JTAG_TRC_PCH_PTI<10>")
	)
	(segment
		(start 380.521464 -46.87824)
		(end 380.521464 -47.2567)
		(width 0.12954)
		(layer "F.Cu")
		(net "JTAG_TRC_PCH_PTI<10>")
	)
	(segment
		(start 381.036322 -46.2407)
		(end 381.036322 -46.61916)
		(width 0.12954)
		(layer "F.Cu")
		(net "JTAG_TRC_PCH_PTI<10>")
	)
	(segment
		(start 380.521464 -42.15638)
		(end 380.651004 -42.28592)
		(width 0.12954)
		(layer "F.Cu")
		(net "JTAG_TRC_PCH_PTI<10>")
	)
	(segment
		(start 380.906782 -39.73576)
		(end 381.036322 -39.8653)
		(width 0.12954)
		(layer "F.Cu")
		(net "JTAG_TRC_PCH_PTI<10>")
	)
	(segment
		(start 381.036322 -42.79392)
		(end 380.906782 -42.92346)
		(width 0.12954)
		(layer "F.Cu")
		(net "JTAG_TRC_PCH_PTI<10>")
	)
	(segment
		(start 341.5538 -21.676868)
		(end 341.5538 -20.08632)
		(width 0.12954)
		(layer "F.Cu")
		(net "JTAG_TRC_PCH_PTI<10>")
	)
	(segment
		(start 341.825072 -28.437586)
		(end 341.825072 -25.69083)
		(width 0.12954)
		(layer "F.Cu")
		(net "JTAG_TRC_PCH_PTI<10>")
	)
	(segment
		(start 345.753182 -15.886938)
		(end 358.44607 -15.886938)
		(width 0.12954)
		(layer "F.Cu")
		(net "JTAG_TRC_PCH_PTI<10>")
	)
	(segment
		(start 380.906782 -48.02378)
		(end 380.651004 -48.02378)
		(width 0.12954)
		(layer "F.Cu")
		(net "JTAG_TRC_PCH_PTI<10>")
	)
	(segment
		(start 381.036322 -40.24376)
		(end 380.906782 -40.3733)
		(width 0.12954)
		(layer "F.Cu")
		(net "JTAG_TRC_PCH_PTI<10>")
	)
	(segment
		(start 380.521464 -50.70348)
		(end 380.521464 -51.351942)
		(width 0.12954)
		(layer "F.Cu")
		(net "JTAG_TRC_PCH_PTI<10>")
	)
	(segment
		(start 381.036322 -43.69054)
		(end 381.036322 -44.069)
		(width 0.12954)
		(layer "F.Cu")
		(net "JTAG_TRC_PCH_PTI<10>")
	)
	(segment
		(start 358.44607 -15.886938)
		(end 380.521464 -37.962332)
		(width 0.12954)
		(layer "F.Cu")
		(net "JTAG_TRC_PCH_PTI<10>")
	)
	(segment
		(start 381.036322 -45.34408)
		(end 380.906782 -45.47362)
		(width 0.12954)
		(layer "F.Cu")
		(net "JTAG_TRC_PCH_PTI<10>")
	)
	(segment
		(start 341.767668 -29.670756)
		(end 341.767668 -28.57627)
		(width 0.12954)
		(layer "F.Cu")
		(net "JTAG_TRC_PCH_PTI<10>")
	)
	(segment
		(start 380.906782 -50.57394)
		(end 380.651004 -50.57394)
		(width 0.12954)
		(layer "F.Cu")
		(net "JTAG_TRC_PCH_PTI<10>")
	)
	(segment
		(start 339.40115 -36.95573)
		(end 339.471 -36.88588)
		(width 0.0889)
		(layer "F.Cu")
		(net "JTAG_TRC_PCH_PTI<10>")
	)
	(via
		(at 387.232906 -54.749954)
		(size 0.508)
		(drill 0.254)
		(layers "F.Cu" "B.Cu")
		(net "JTAG_TRC_PCH_PTI<10>")
	)
	(via
		(at 383.275586 -54.813708)
		(size 0.508)
		(drill 0.254)
		(layers "F.Cu" "B.Cu")
		(net "JTAG_TRC_PCH_PTI<10>")
	)
	(segment
		(start 384.841242 -55.420514)
		(end 386.562346 -55.420514)
		(width 0.12954)
		(layer "B.Cu")
		(net "JTAG_TRC_PCH_PTI<10>")
	)
	(segment
		(start 383.332482 -55.420514)
		(end 383.944622 -55.420514)
		(width 0.12954)
		(layer "B.Cu")
		(net "JTAG_TRC_PCH_PTI<10>")
	)
	(segment
		(start 384.074162 -53.46319)
		(end 384.203702 -53.33365)
		(width 0.12954)
		(layer "B.Cu")
		(net "JTAG_TRC_PCH_PTI<10>")
	)
	(segment
		(start 383.275586 -54.813708)
		(end 383.275586 -55.363618)
		(width 0.12954)
		(layer "B.Cu")
		(net "JTAG_TRC_PCH_PTI<10>")
	)
	(segment
		(start 384.582162 -53.33365)
		(end 384.711702 -53.46319)
		(width 0.12954)
		(layer "B.Cu")
		(net "JTAG_TRC_PCH_PTI<10>")
	)
	(segment
		(start 384.074162 -55.290974)
		(end 384.074162 -53.46319)
		(width 0.12954)
		(layer "B.Cu")
		(net "JTAG_TRC_PCH_PTI<10>")
	)
	(segment
		(start 384.711702 -55.290974)
		(end 384.841242 -55.420514)
		(width 0.12954)
		(layer "B.Cu")
		(net "JTAG_TRC_PCH_PTI<10>")
	)
	(segment
		(start 384.203702 -53.33365)
		(end 384.582162 -53.33365)
		(width 0.12954)
		(layer "B.Cu")
		(net "JTAG_TRC_PCH_PTI<10>")
	)
	(segment
		(start 384.711702 -53.46319)
		(end 384.711702 -55.290974)
		(width 0.12954)
		(layer "B.Cu")
		(net "JTAG_TRC_PCH_PTI<10>")
	)
	(segment
		(start 383.944622 -55.420514)
		(end 384.074162 -55.290974)
		(width 0.12954)
		(layer "B.Cu")
		(net "JTAG_TRC_PCH_PTI<10>")
	)
	(segment
		(start 383.275586 -55.363618)
		(end 383.332482 -55.420514)
		(width 0.12954)
		(layer "B.Cu")
		(net "JTAG_TRC_PCH_PTI<10>")
	)
	(segment
		(start 386.562346 -55.420514)
		(end 387.232906 -54.749954)
		(width 0.12954)
		(layer "B.Cu")
		(net "JTAG_TRC_PCH_PTI<10>")
	)
	(segment
		(start 371.288818 -34.862262)
		(end 371.55628 -35.129724)
		(width 0.12954)
		(layer "F.Cu")
		(net "JTAG_TRC_PCH_PTI<0>")
	)
	(segment
		(start 367.231168 -30.621224)
		(end 367.424716 -30.427676)
		(width 0.12954)
		(layer "F.Cu")
		(net "JTAG_TRC_PCH_PTI<0>")
	)
	(segment
		(start 370.387118 -33.777174)
		(end 370.387118 -33.960562)
		(width 0.12954)
		(layer "F.Cu")
		(net "JTAG_TRC_PCH_PTI<0>")
	)
	(segment
		(start 342.402668 -36.797234)
		(end 342.730836 -36.469066)
		(width 0.0889)
		(layer "F.Cu")
		(net "JTAG_TRC_PCH_PTI<0>")
	)
	(segment
		(start 342.561418 -37.233098)
		(end 342.402668 -37.074348)
		(width 0.0889)
		(layer "F.Cu")
		(net "JTAG_TRC_PCH_PTI<0>")
	)
	(segment
		(start 362.014516 -25.017476)
		(end 362.197904 -25.017476)
		(width 0.12954)
		(layer "F.Cu")
		(net "JTAG_TRC_PCH_PTI<0>")
	)
	(segment
		(start 372.384066 -35.203638)
		(end 372.384066 -35.387026)
		(width 0.12954)
		(layer "F.Cu")
		(net "JTAG_TRC_PCH_PTI<0>")
	)
	(segment
		(start 371.482366 -34.301938)
		(end 371.482366 -34.485326)
		(width 0.12954)
		(layer "F.Cu")
		(net "JTAG_TRC_PCH_PTI<0>")
	)
	(segment
		(start 368.777266 -31.596838)
		(end 368.777266 -31.780226)
		(width 0.12954)
		(layer "F.Cu")
		(net "JTAG_TRC_PCH_PTI<0>")
	)
	(segment
		(start 365.878618 -29.268674)
		(end 365.878618 -29.452062)
		(width 0.12954)
		(layer "F.Cu")
		(net "JTAG_TRC_PCH_PTI<0>")
	)
	(segment
		(start 358.214168 -21.604224)
		(end 358.407716 -21.410676)
		(width 0.12954)
		(layer "F.Cu")
		(net "JTAG_TRC_PCH_PTI<0>")
	)
	(segment
		(start 371.933216 -34.936176)
		(end 372.116604 -34.936176)
		(width 0.12954)
		(layer "F.Cu")
		(net "JTAG_TRC_PCH_PTI<0>")
	)
	(segment
		(start 359.566718 -22.956774)
		(end 359.566718 -23.140162)
		(width 0.12954)
		(layer "F.Cu")
		(net "JTAG_TRC_PCH_PTI<0>")
	)
	(segment
		(start 374.209564 -37.029136)
		(end 374.209564 -37.212524)
		(width 0.12954)
		(layer "F.Cu")
		(net "JTAG_TRC_PCH_PTI<0>")
	)
	(segment
		(start 358.03078 -21.604224)
		(end 358.214168 -21.604224)
		(width 0.12954)
		(layer "F.Cu")
		(net "JTAG_TRC_PCH_PTI<0>")
	)
	(segment
		(start 374.148858 -37.991542)
		(end 374.332246 -37.991542)
		(width 0.12954)
		(layer "F.Cu")
		(net "JTAG_TRC_PCH_PTI<0>")
	)
	(segment
		(start 367.608104 -30.427676)
		(end 367.875566 -30.695138)
		(width 0.12954)
		(layer "F.Cu")
		(net "JTAG_TRC_PCH_PTI<0>")
	)
	(segment
		(start 382.86436 -59.578748)
		(end 384.34772 -58.095388)
		(width 0.12954)
		(layer "F.Cu")
		(net "JTAG_TRC_PCH_PTI<0>")
	)
	(segment
		(start 362.197904 -25.017476)
		(end 362.465366 -25.284938)
		(width 0.12954)
		(layer "F.Cu")
		(net "JTAG_TRC_PCH_PTI<0>")
	)
	(segment
		(start 360.017568 -23.407624)
		(end 360.211116 -23.214076)
		(width 0.12954)
		(layer "F.Cu")
		(net "JTAG_TRC_PCH_PTI<0>")
	)
	(segment
		(start 366.072166 -29.075126)
		(end 365.878618 -29.268674)
		(width 0.12954)
		(layer "F.Cu")
		(net "JTAG_TRC_PCH_PTI<0>")
	)
	(segment
		(start 357.12908 -20.702524)
		(end 357.312468 -20.702524)
		(width 0.12954)
		(layer "F.Cu")
		(net "JTAG_TRC_PCH_PTI<0>")
	)
	(segment
		(start 369.75288 -33.326324)
		(end 369.936268 -33.326324)
		(width 0.12954)
		(layer "F.Cu")
		(net "JTAG_TRC_PCH_PTI<0>")
	)
	(segment
		(start 357.312468 -20.702524)
		(end 357.506016 -20.508976)
		(width 0.12954)
		(layer "F.Cu")
		(net "JTAG_TRC_PCH_PTI<0>")
	)
	(segment
		(start 358.591104 -21.410676)
		(end 358.858566 -21.678138)
		(width 0.12954)
		(layer "F.Cu")
		(net "JTAG_TRC_PCH_PTI<0>")
	)
	(segment
		(start 358.858566 -21.678138)
		(end 358.858566 -21.861526)
		(width 0.12954)
		(layer "F.Cu")
		(net "JTAG_TRC_PCH_PTI<0>")
	)
	(segment
		(start 360.468418 -24.041862)
		(end 360.73588 -24.309324)
		(width 0.12954)
		(layer "F.Cu")
		(net "JTAG_TRC_PCH_PTI<0>")
	)
	(segment
		(start 369.485418 -33.058862)
		(end 369.75288 -33.326324)
		(width 0.12954)
		(layer "F.Cu")
		(net "JTAG_TRC_PCH_PTI<0>")
	)
	(segment
		(start 357.506016 -20.508976)
		(end 357.689404 -20.508976)
		(width 0.12954)
		(layer "F.Cu")
		(net "JTAG_TRC_PCH_PTI<0>")
	)
	(segment
		(start 367.682018 -31.072074)
		(end 367.682018 -31.255462)
		(width 0.12954)
		(layer "F.Cu")
		(net "JTAG_TRC_PCH_PTI<0>")
	)
	(segment
		(start 364.268766 -27.271726)
		(end 364.075218 -27.465274)
		(width 0.12954)
		(layer "F.Cu")
		(net "JTAG_TRC_PCH_PTI<0>")
	)
	(segment
		(start 361.370118 -24.760174)
		(end 361.370118 -24.943562)
		(width 0.12954)
		(layer "F.Cu")
		(net "JTAG_TRC_PCH_PTI<0>")
	)
	(segment
		(start 362.271818 -25.845262)
		(end 362.53928 -26.112724)
		(width 0.12954)
		(layer "F.Cu")
		(net "JTAG_TRC_PCH_PTI<0>")
	)
	(segment
		(start 360.211116 -23.214076)
		(end 360.394504 -23.214076)
		(width 0.12954)
		(layer "F.Cu")
		(net "JTAG_TRC_PCH_PTI<0>")
	)
	(segment
		(start 361.820968 -25.211024)
		(end 362.014516 -25.017476)
		(width 0.12954)
		(layer "F.Cu")
		(net "JTAG_TRC_PCH_PTI<0>")
	)
	(segment
		(start 361.370118 -24.943562)
		(end 361.63758 -25.211024)
		(width 0.12954)
		(layer "F.Cu")
		(net "JTAG_TRC_PCH_PTI<0>")
	)
	(segment
		(start 371.031516 -34.034476)
		(end 371.214904 -34.034476)
		(width 0.12954)
		(layer "F.Cu")
		(net "JTAG_TRC_PCH_PTI<0>")
	)
	(segment
		(start 368.777266 -31.780226)
		(end 368.583718 -31.973774)
		(width 0.12954)
		(layer "F.Cu")
		(net "JTAG_TRC_PCH_PTI<0>")
	)
	(segment
		(start 359.309416 -22.312376)
		(end 359.492804 -22.312376)
		(width 0.12954)
		(layer "F.Cu")
		(net "JTAG_TRC_PCH_PTI<0>")
	)
	(segment
		(start 357.956866 -20.776438)
		(end 357.956866 -20.959826)
		(width 0.12954)
		(layer "F.Cu")
		(net "JTAG_TRC_PCH_PTI<0>")
	)
	(segment
		(start 370.313204 -33.132776)
		(end 370.580666 -33.400238)
		(width 0.12954)
		(layer "F.Cu")
		(net "JTAG_TRC_PCH_PTI<0>")
	)
	(segment
		(start 360.661966 -23.481538)
		(end 360.661966 -23.664926)
		(width 0.12954)
		(layer "F.Cu")
		(net "JTAG_TRC_PCH_PTI<0>")
	)
	(segment
		(start 364.719616 -27.722576)
		(end 364.903004 -27.722576)
		(width 0.12954)
		(layer "F.Cu")
		(net "JTAG_TRC_PCH_PTI<0>")
	)
	(segment
		(start 361.563666 -24.383238)
		(end 361.563666 -24.566626)
		(width 0.12954)
		(layer "F.Cu")
		(net "JTAG_TRC_PCH_PTI<0>")
	)
	(segment
		(start 388.137146 -59.749944)
		(end 392.034776 -59.749944)
		(width 0.12954)
		(layer "F.Cu")
		(net "JTAG_TRC_PCH_PTI<0>")
	)
	(segment
		(start 362.465366 -25.284938)
		(end 362.465366 -25.468326)
		(width 0.12954)
		(layer "F.Cu")
		(net "JTAG_TRC_PCH_PTI<0>")
	)
	(segment
		(start 365.427768 -28.817824)
		(end 365.621316 -28.624276)
		(width 0.12954)
		(layer "F.Cu")
		(net "JTAG_TRC_PCH_PTI<0>")
	)
	(segment
		(start 363.099604 -25.919176)
		(end 363.367066 -26.186638)
		(width 0.12954)
		(layer "F.Cu")
		(net "JTAG_TRC_PCH_PTI<0>")
	)
	(segment
		(start 368.583718 -31.973774)
		(end 368.583718 -32.157162)
		(width 0.12954)
		(layer "F.Cu")
		(net "JTAG_TRC_PCH_PTI<0>")
	)
	(segment
		(start 366.973866 -29.976826)
		(end 366.780318 -30.170374)
		(width 0.12954)
		(layer "F.Cu")
		(net "JTAG_TRC_PCH_PTI<0>")
	)
	(segment
		(start 372.116604 -34.936176)
		(end 372.384066 -35.203638)
		(width 0.12954)
		(layer "F.Cu")
		(net "JTAG_TRC_PCH_PTI<0>")
	)
	(segment
		(start 366.973866 -29.793438)
		(end 366.973866 -29.976826)
		(width 0.12954)
		(layer "F.Cu")
		(net "JTAG_TRC_PCH_PTI<0>")
	)
	(segment
		(start 380.007368 -59.578748)
		(end 382.138936 -59.578748)
		(width 0.12954)
		(layer "F.Cu")
		(net "JTAG_TRC_PCH_PTI<0>")
	)
	(segment
		(start 374.332246 -37.991542)
		(end 374.660414 -37.663374)
		(width 0.12954)
		(layer "F.Cu")
		(net "JTAG_TRC_PCH_PTI<0>")
	)
	(segment
		(start 364.075218 -27.465274)
		(end 364.075218 -27.648662)
		(width 0.12954)
		(layer "F.Cu")
		(net "JTAG_TRC_PCH_PTI<0>")
	)
	(segment
		(start 343.684606 -35.422078)
		(end 345.385644 -33.72104)
		(width 0.12954)
		(layer "F.Cu")
		(net "JTAG_TRC_PCH_PTI<0>")
	)
	(segment
		(start 364.976918 -28.550362)
		(end 365.24438 -28.817824)
		(width 0.12954)
		(layer "F.Cu")
		(net "JTAG_TRC_PCH_PTI<0>")
	)
	(segment
		(start 363.624368 -27.014424)
		(end 363.817916 -26.820876)
		(width 0.12954)
		(layer "F.Cu")
		(net "JTAG_TRC_PCH_PTI<0>")
	)
	(segment
		(start 366.072166 -28.891738)
		(end 366.072166 -29.075126)
		(width 0.12954)
		(layer "F.Cu")
		(net "JTAG_TRC_PCH_PTI<0>")
	)
	(segment
		(start 365.170466 -27.990038)
		(end 365.170466 -28.173426)
		(width 0.12954)
		(layer "F.Cu")
		(net "JTAG_TRC_PCH_PTI<0>")
	)
	(segment
		(start 343.55405 -35.753548)
		(end 343.55405 -35.552634)
		(width 0.0889)
		(layer "F.Cu")
		(net "JTAG_TRC_PCH_PTI<0>")
	)
	(segment
		(start 359.566718 -23.140162)
		(end 359.83418 -23.407624)
		(width 0.12954)
		(layer "F.Cu")
		(net "JTAG_TRC_PCH_PTI<0>")
	)
	(segment
		(start 346.0369 -27.120088)
		(end 346.0369 -20.552664)
		(width 0.12954)
		(layer "F.Cu")
		(net "JTAG_TRC_PCH_PTI<0>")
	)
	(segment
		(start 373.018304 -35.837876)
		(end 374.209564 -37.029136)
		(width 0.12954)
		(layer "F.Cu")
		(net "JTAG_TRC_PCH_PTI<0>")
	)
	(segment
		(start 358.407716 -21.410676)
		(end 358.591104 -21.410676)
		(width 0.12954)
		(layer "F.Cu")
		(net "JTAG_TRC_PCH_PTI<0>")
	)
	(segment
		(start 374.843802 -37.663374)
		(end 375.4628 -38.282372)
		(width 0.12954)
		(layer "F.Cu")
		(net "JTAG_TRC_PCH_PTI<0>")
	)
	(segment
		(start 371.214904 -34.034476)
		(end 371.482366 -34.301938)
		(width 0.12954)
		(layer "F.Cu")
		(net "JTAG_TRC_PCH_PTI<0>")
	)
	(segment
		(start 367.94948 -31.522924)
		(end 368.132868 -31.522924)
		(width 0.12954)
		(layer "F.Cu")
		(net "JTAG_TRC_PCH_PTI<0>")
	)
	(segment
		(start 371.739668 -35.129724)
		(end 371.933216 -34.936176)
		(width 0.12954)
		(layer "F.Cu")
		(net "JTAG_TRC_PCH_PTI<0>")
	)
	(segment
		(start 357.956866 -20.959826)
		(end 357.763318 -21.153374)
		(width 0.12954)
		(layer "F.Cu")
		(net "JTAG_TRC_PCH_PTI<0>")
	)
	(segment
		(start 360.73588 -24.309324)
		(end 360.919268 -24.309324)
		(width 0.12954)
		(layer "F.Cu")
		(net "JTAG_TRC_PCH_PTI<0>")
	)
	(segment
		(start 372.834916 -35.837876)
		(end 373.018304 -35.837876)
		(width 0.12954)
		(layer "F.Cu")
		(net "JTAG_TRC_PCH_PTI<0>")
	)
	(segment
		(start 364.001304 -26.820876)
		(end 364.268766 -27.088338)
		(width 0.12954)
		(layer "F.Cu")
		(net "JTAG_TRC_PCH_PTI<0>")
	)
	(segment
		(start 364.268766 -27.088338)
		(end 364.268766 -27.271726)
		(width 0.12954)
		(layer "F.Cu")
		(net "JTAG_TRC_PCH_PTI<0>")
	)
	(segment
		(start 369.678966 -32.681926)
		(end 369.485418 -32.875474)
		(width 0.12954)
		(layer "F.Cu")
		(net "JTAG_TRC_PCH_PTI<0>")
	)
	(segment
		(start 361.296204 -24.115776)
		(end 361.563666 -24.383238)
		(width 0.12954)
		(layer "F.Cu")
		(net "JTAG_TRC_PCH_PTI<0>")
	)
	(segment
		(start 372.190518 -35.580574)
		(end 372.190518 -35.763962)
		(width 0.12954)
		(layer "F.Cu")
		(net "JTAG_TRC_PCH_PTI<0>")
	)
	(segment
		(start 356.621842 -19.441414)
		(end 357.055166 -19.874738)
		(width 0.12954)
		(layer "F.Cu")
		(net "JTAG_TRC_PCH_PTI<0>")
	)
	(segment
		(start 363.367066 -26.186638)
		(end 363.367066 -26.370026)
		(width 0.12954)
		(layer "F.Cu")
		(net "JTAG_TRC_PCH_PTI<0>")
	)
	(segment
		(start 345.856306 -29.394404)
		(end 345.856306 -27.556206)
		(width 0.12954)
		(layer "F.Cu")
		(net "JTAG_TRC_PCH_PTI<0>")
	)
	(segment
		(start 372.45798 -36.031424)
		(end 372.641368 -36.031424)
		(width 0.12954)
		(layer "F.Cu")
		(net "JTAG_TRC_PCH_PTI<0>")
	)
	(segment
		(start 374.209564 -37.212524)
		(end 373.881396 -37.540692)
		(width 0.12954)
		(layer "F.Cu")
		(net "JTAG_TRC_PCH_PTI<0>")
	)
	(segment
		(start 367.682018 -31.255462)
		(end 367.94948 -31.522924)
		(width 0.12954)
		(layer "F.Cu")
		(net "JTAG_TRC_PCH_PTI<0>")
	)
	(segment
		(start 360.468418 -23.858474)
		(end 360.468418 -24.041862)
		(width 0.12954)
		(layer "F.Cu")
		(net "JTAG_TRC_PCH_PTI<0>")
	)
	(segment
		(start 361.112816 -24.115776)
		(end 361.296204 -24.115776)
		(width 0.12954)
		(layer "F.Cu")
		(net "JTAG_TRC_PCH_PTI<0>")
	)
	(segment
		(start 374.660414 -37.663374)
		(end 374.843802 -37.663374)
		(width 0.12954)
		(layer "F.Cu")
		(net "JTAG_TRC_PCH_PTI<0>")
	)
	(segment
		(start 369.936268 -33.326324)
		(end 370.129816 -33.132776)
		(width 0.12954)
		(layer "F.Cu")
		(net "JTAG_TRC_PCH_PTI<0>")
	)
	(segment
		(start 357.763318 -21.336762)
		(end 358.03078 -21.604224)
		(width 0.12954)
		(layer "F.Cu")
		(net "JTAG_TRC_PCH_PTI<0>")
	)
	(segment
		(start 362.271818 -25.661874)
		(end 362.271818 -25.845262)
		(width 0.12954)
		(layer "F.Cu")
		(net "JTAG_TRC_PCH_PTI<0>")
	)
	(segment
		(start 342.838532 -36.469066)
		(end 343.55405 -35.753548)
		(width 0.0889)
		(layer "F.Cu")
		(net "JTAG_TRC_PCH_PTI<0>")
	)
	(segment
		(start 357.055166 -20.058126)
		(end 356.861618 -20.251674)
		(width 0.12954)
		(layer "F.Cu")
		(net "JTAG_TRC_PCH_PTI<0>")
	)
	(segment
		(start 366.780318 -30.353762)
		(end 367.04778 -30.621224)
		(width 0.12954)
		(layer "F.Cu")
		(net "JTAG_TRC_PCH_PTI<0>")
	)
	(segment
		(start 366.329468 -29.719524)
		(end 366.523016 -29.525976)
		(width 0.12954)
		(layer "F.Cu")
		(net "JTAG_TRC_PCH_PTI<0>")
	)
	(segment
		(start 372.384066 -35.387026)
		(end 372.190518 -35.580574)
		(width 0.12954)
		(layer "F.Cu")
		(net "JTAG_TRC_PCH_PTI<0>")
	)
	(segment
		(start 341.902034 -38.465252)
		(end 342.447118 -38.465252)
		(width 0.0889)
		(layer "F.Cu")
		(net "JTAG_TRC_PCH_PTI<0>")
	)
	(segment
		(start 368.132868 -31.522924)
		(end 368.326416 -31.329376)
		(width 0.12954)
		(layer "F.Cu")
		(net "JTAG_TRC_PCH_PTI<0>")
	)
	(segment
		(start 345.385644 -33.72104)
		(end 345.385644 -29.865066)
		(width 0.12954)
		(layer "F.Cu")
		(net "JTAG_TRC_PCH_PTI<0>")
	)
	(segment
		(start 363.173518 -26.563574)
		(end 363.173518 -26.746962)
		(width 0.12954)
		(layer "F.Cu")
		(net "JTAG_TRC_PCH_PTI<0>")
	)
	(segment
		(start 367.875566 -30.878526)
		(end 367.682018 -31.072074)
		(width 0.12954)
		(layer "F.Cu")
		(net "JTAG_TRC_PCH_PTI<0>")
	)
	(segment
		(start 369.034568 -32.424624)
		(end 369.228116 -32.231076)
		(width 0.12954)
		(layer "F.Cu")
		(net "JTAG_TRC_PCH_PTI<0>")
	)
	(segment
		(start 359.83418 -23.407624)
		(end 360.017568 -23.407624)
		(width 0.12954)
		(layer "F.Cu")
		(net "JTAG_TRC_PCH_PTI<0>")
	)
	(segment
		(start 365.170466 -28.173426)
		(end 364.976918 -28.366974)
		(width 0.12954)
		(layer "F.Cu")
		(net "JTAG_TRC_PCH_PTI<0>")
	)
	(segment
		(start 367.875566 -30.695138)
		(end 367.875566 -30.878526)
		(width 0.12954)
		(layer "F.Cu")
		(net "JTAG_TRC_PCH_PTI<0>")
	)
	(segment
		(start 368.583718 -32.157162)
		(end 368.85118 -32.424624)
		(width 0.12954)
		(layer "F.Cu")
		(net "JTAG_TRC_PCH_PTI<0>")
	)
	(segment
		(start 370.65458 -34.228024)
		(end 370.837968 -34.228024)
		(width 0.12954)
		(layer "F.Cu")
		(net "JTAG_TRC_PCH_PTI<0>")
	)
	(segment
		(start 358.665018 -22.055074)
		(end 358.665018 -22.238462)
		(width 0.12954)
		(layer "F.Cu")
		(net "JTAG_TRC_PCH_PTI<0>")
	)
	(segment
		(start 358.93248 -22.505924)
		(end 359.115868 -22.505924)
		(width 0.12954)
		(layer "F.Cu")
		(net "JTAG_TRC_PCH_PTI<0>")
	)
	(segment
		(start 362.722668 -26.112724)
		(end 362.916216 -25.919176)
		(width 0.12954)
		(layer "F.Cu")
		(net "JTAG_TRC_PCH_PTI<0>")
	)
	(segment
		(start 373.881396 -37.540692)
		(end 373.881396 -37.72408)
		(width 0.12954)
		(layer "F.Cu")
		(net "JTAG_TRC_PCH_PTI<0>")
	)
	(segment
		(start 363.367066 -26.370026)
		(end 363.173518 -26.563574)
		(width 0.12954)
		(layer "F.Cu")
		(net "JTAG_TRC_PCH_PTI<0>")
	)
	(segment
		(start 342.402668 -37.074348)
		(end 342.402668 -36.797234)
		(width 0.0889)
		(layer "F.Cu")
		(net "JTAG_TRC_PCH_PTI<0>")
	)
	(segment
		(start 371.482366 -34.485326)
		(end 371.288818 -34.678874)
		(width 0.12954)
		(layer "F.Cu")
		(net "JTAG_TRC_PCH_PTI<0>")
	)
	(segment
		(start 372.641368 -36.031424)
		(end 372.834916 -35.837876)
		(width 0.12954)
		(layer "F.Cu")
		(net "JTAG_TRC_PCH_PTI<0>")
	)
	(segment
		(start 366.523016 -29.525976)
		(end 366.706404 -29.525976)
		(width 0.12954)
		(layer "F.Cu")
		(net "JTAG_TRC_PCH_PTI<0>")
	)
	(segment
		(start 372.190518 -35.763962)
		(end 372.45798 -36.031424)
		(width 0.12954)
		(layer "F.Cu")
		(net "JTAG_TRC_PCH_PTI<0>")
	)
	(segment
		(start 356.861618 -20.435062)
		(end 357.12908 -20.702524)
		(width 0.12954)
		(layer "F.Cu")
		(net "JTAG_TRC_PCH_PTI<0>")
	)
	(segment
		(start 356.861618 -20.251674)
		(end 356.861618 -20.435062)
		(width 0.12954)
		(layer "F.Cu")
		(net "JTAG_TRC_PCH_PTI<0>")
	)
	(segment
		(start 362.916216 -25.919176)
		(end 363.099604 -25.919176)
		(width 0.12954)
		(layer "F.Cu")
		(net "JTAG_TRC_PCH_PTI<0>")
	)
	(segment
		(start 365.804704 -28.624276)
		(end 366.072166 -28.891738)
		(width 0.12954)
		(layer "F.Cu")
		(net "JTAG_TRC_PCH_PTI<0>")
	)
	(segment
		(start 367.04778 -30.621224)
		(end 367.231168 -30.621224)
		(width 0.12954)
		(layer "F.Cu")
		(net "JTAG_TRC_PCH_PTI<0>")
	)
	(segment
		(start 342.720422 -38.191948)
		(end 342.720422 -37.991034)
		(width 0.0889)
		(layer "F.Cu")
		(net "JTAG_TRC_PCH_PTI<0>")
	)
	(segment
		(start 368.509804 -31.329376)
		(end 368.777266 -31.596838)
		(width 0.12954)
		(layer "F.Cu")
		(net "JTAG_TRC_PCH_PTI<0>")
	)
	(segment
		(start 357.689404 -20.508976)
		(end 357.956866 -20.776438)
		(width 0.12954)
		(layer "F.Cu")
		(net "JTAG_TRC_PCH_PTI<0>")
	)
	(segment
		(start 368.85118 -32.424624)
		(end 369.034568 -32.424624)
		(width 0.12954)
		(layer "F.Cu")
		(net "JTAG_TRC_PCH_PTI<0>")
	)
	(segment
		(start 365.878618 -29.452062)
		(end 366.14608 -29.719524)
		(width 0.12954)
		(layer "F.Cu")
		(net "JTAG_TRC_PCH_PTI<0>")
	)
	(segment
		(start 370.129816 -33.132776)
		(end 370.313204 -33.132776)
		(width 0.12954)
		(layer "F.Cu")
		(net "JTAG_TRC_PCH_PTI<0>")
	)
	(segment
		(start 375.4628 -55.03418)
		(end 380.007368 -59.578748)
		(width 0.12954)
		(layer "F.Cu")
		(net "JTAG_TRC_PCH_PTI<0>")
	)
	(segment
		(start 342.561418 -37.606732)
		(end 342.561418 -37.233098)
		(width 0.0889)
		(layer "F.Cu")
		(net "JTAG_TRC_PCH_PTI<0>")
	)
	(segment
		(start 382.138936 -59.578748)
		(end 382.86436 -59.578748)
		(width 0.12954)
		(layer "F.Cu")
		(net "JTAG_TRC_PCH_PTI<0>")
	)
	(segment
		(start 371.288818 -34.678874)
		(end 371.288818 -34.862262)
		(width 0.12954)
		(layer "F.Cu")
		(net "JTAG_TRC_PCH_PTI<0>")
	)
	(segment
		(start 342.720422 -37.991034)
		(end 342.561418 -37.606732)
		(width 0.0889)
		(layer "F.Cu")
		(net "JTAG_TRC_PCH_PTI<0>")
	)
	(segment
		(start 367.424716 -30.427676)
		(end 367.608104 -30.427676)
		(width 0.12954)
		(layer "F.Cu")
		(net "JTAG_TRC_PCH_PTI<0>")
	)
	(segment
		(start 371.55628 -35.129724)
		(end 371.739668 -35.129724)
		(width 0.12954)
		(layer "F.Cu")
		(net "JTAG_TRC_PCH_PTI<0>")
	)
	(segment
		(start 364.075218 -27.648662)
		(end 364.34268 -27.916124)
		(width 0.12954)
		(layer "F.Cu")
		(net "JTAG_TRC_PCH_PTI<0>")
	)
	(segment
		(start 358.665018 -22.238462)
		(end 358.93248 -22.505924)
		(width 0.12954)
		(layer "F.Cu")
		(net "JTAG_TRC_PCH_PTI<0>")
	)
	(segment
		(start 343.55405 -35.552634)
		(end 343.684606 -35.422078)
		(width 0.0889)
		(layer "F.Cu")
		(net "JTAG_TRC_PCH_PTI<0>")
	)
	(segment
		(start 363.44098 -27.014424)
		(end 363.624368 -27.014424)
		(width 0.12954)
		(layer "F.Cu")
		(net "JTAG_TRC_PCH_PTI<0>")
	)
	(segment
		(start 386.48259 -58.095388)
		(end 388.137146 -59.749944)
		(width 0.12954)
		(layer "F.Cu")
		(net "JTAG_TRC_PCH_PTI<0>")
	)
	(segment
		(start 364.526068 -27.916124)
		(end 364.719616 -27.722576)
		(width 0.12954)
		(layer "F.Cu")
		(net "JTAG_TRC_PCH_PTI<0>")
	)
	(segment
		(start 361.63758 -25.211024)
		(end 361.820968 -25.211024)
		(width 0.12954)
		(layer "F.Cu")
		(net "JTAG_TRC_PCH_PTI<0>")
	)
	(segment
		(start 370.580666 -33.400238)
		(end 370.580666 -33.583626)
		(width 0.12954)
		(layer "F.Cu")
		(net "JTAG_TRC_PCH_PTI<0>")
	)
	(segment
		(start 360.919268 -24.309324)
		(end 361.112816 -24.115776)
		(width 0.12954)
		(layer "F.Cu")
		(net "JTAG_TRC_PCH_PTI<0>")
	)
	(segment
		(start 369.411504 -32.231076)
		(end 369.678966 -32.498538)
		(width 0.12954)
		(layer "F.Cu")
		(net "JTAG_TRC_PCH_PTI<0>")
	)
	(segment
		(start 345.385644 -29.865066)
		(end 345.856306 -29.394404)
		(width 0.12954)
		(layer "F.Cu")
		(net "JTAG_TRC_PCH_PTI<0>")
	)
	(segment
		(start 359.115868 -22.505924)
		(end 359.309416 -22.312376)
		(width 0.12954)
		(layer "F.Cu")
		(net "JTAG_TRC_PCH_PTI<0>")
	)
	(segment
		(start 362.465366 -25.468326)
		(end 362.271818 -25.661874)
		(width 0.12954)
		(layer "F.Cu")
		(net "JTAG_TRC_PCH_PTI<0>")
	)
	(segment
		(start 365.24438 -28.817824)
		(end 365.427768 -28.817824)
		(width 0.12954)
		(layer "F.Cu")
		(net "JTAG_TRC_PCH_PTI<0>")
	)
	(segment
		(start 384.34772 -58.095388)
		(end 386.48259 -58.095388)
		(width 0.12954)
		(layer "F.Cu")
		(net "JTAG_TRC_PCH_PTI<0>")
	)
	(segment
		(start 365.621316 -28.624276)
		(end 365.804704 -28.624276)
		(width 0.12954)
		(layer "F.Cu")
		(net "JTAG_TRC_PCH_PTI<0>")
	)
	(segment
		(start 370.580666 -33.583626)
		(end 370.387118 -33.777174)
		(width 0.12954)
		(layer "F.Cu")
		(net "JTAG_TRC_PCH_PTI<0>")
	)
	(segment
		(start 370.837968 -34.228024)
		(end 371.031516 -34.034476)
		(width 0.12954)
		(layer "F.Cu")
		(net "JTAG_TRC_PCH_PTI<0>")
	)
	(segment
		(start 366.14608 -29.719524)
		(end 366.329468 -29.719524)
		(width 0.12954)
		(layer "F.Cu")
		(net "JTAG_TRC_PCH_PTI<0>")
	)
	(segment
		(start 357.055166 -19.874738)
		(end 357.055166 -20.058126)
		(width 0.12954)
		(layer "F.Cu")
		(net "JTAG_TRC_PCH_PTI<0>")
	)
	(segment
		(start 370.387118 -33.960562)
		(end 370.65458 -34.228024)
		(width 0.12954)
		(layer "F.Cu")
		(net "JTAG_TRC_PCH_PTI<0>")
	)
	(segment
		(start 375.4628 -38.282372)
		(end 375.4628 -55.03418)
		(width 0.12954)
		(layer "F.Cu")
		(net "JTAG_TRC_PCH_PTI<0>")
	)
	(segment
		(start 366.706404 -29.525976)
		(end 366.973866 -29.793438)
		(width 0.12954)
		(layer "F.Cu")
		(net "JTAG_TRC_PCH_PTI<0>")
	)
	(segment
		(start 360.394504 -23.214076)
		(end 360.661966 -23.481538)
		(width 0.12954)
		(layer "F.Cu")
		(net "JTAG_TRC_PCH_PTI<0>")
	)
	(segment
		(start 359.492804 -22.312376)
		(end 359.760266 -22.579838)
		(width 0.12954)
		(layer "F.Cu")
		(net "JTAG_TRC_PCH_PTI<0>")
	)
	(segment
		(start 366.780318 -30.170374)
		(end 366.780318 -30.353762)
		(width 0.12954)
		(layer "F.Cu")
		(net "JTAG_TRC_PCH_PTI<0>")
	)
	(segment
		(start 358.858566 -21.861526)
		(end 358.665018 -22.055074)
		(width 0.12954)
		(layer "F.Cu")
		(net "JTAG_TRC_PCH_PTI<0>")
	)
	(segment
		(start 363.817916 -26.820876)
		(end 364.001304 -26.820876)
		(width 0.12954)
		(layer "F.Cu")
		(net "JTAG_TRC_PCH_PTI<0>")
	)
	(segment
		(start 364.903004 -27.722576)
		(end 365.170466 -27.990038)
		(width 0.12954)
		(layer "F.Cu")
		(net "JTAG_TRC_PCH_PTI<0>")
	)
	(segment
		(start 360.661966 -23.664926)
		(end 360.468418 -23.858474)
		(width 0.12954)
		(layer "F.Cu")
		(net "JTAG_TRC_PCH_PTI<0>")
	)
	(segment
		(start 342.730836 -36.469066)
		(end 342.838532 -36.469066)
		(width 0.0889)
		(layer "F.Cu")
		(net "JTAG_TRC_PCH_PTI<0>")
	)
	(segment
		(start 373.881396 -37.72408)
		(end 374.148858 -37.991542)
		(width 0.12954)
		(layer "F.Cu")
		(net "JTAG_TRC_PCH_PTI<0>")
	)
	(segment
		(start 364.34268 -27.916124)
		(end 364.526068 -27.916124)
		(width 0.12954)
		(layer "F.Cu")
		(net "JTAG_TRC_PCH_PTI<0>")
	)
	(segment
		(start 363.173518 -26.746962)
		(end 363.44098 -27.014424)
		(width 0.12954)
		(layer "F.Cu")
		(net "JTAG_TRC_PCH_PTI<0>")
	)
	(segment
		(start 346.0369 -20.552664)
		(end 347.14815 -19.441414)
		(width 0.12954)
		(layer "F.Cu")
		(net "JTAG_TRC_PCH_PTI<0>")
	)
	(segment
		(start 342.447118 -38.465252)
		(end 342.720422 -38.191948)
		(width 0.0889)
		(layer "F.Cu")
		(net "JTAG_TRC_PCH_PTI<0>")
	)
	(segment
		(start 362.53928 -26.112724)
		(end 362.722668 -26.112724)
		(width 0.12954)
		(layer "F.Cu")
		(net "JTAG_TRC_PCH_PTI<0>")
	)
	(segment
		(start 368.326416 -31.329376)
		(end 368.509804 -31.329376)
		(width 0.12954)
		(layer "F.Cu")
		(net "JTAG_TRC_PCH_PTI<0>")
	)
	(segment
		(start 359.760266 -22.579838)
		(end 359.760266 -22.763226)
		(width 0.12954)
		(layer "F.Cu")
		(net "JTAG_TRC_PCH_PTI<0>")
	)
	(segment
		(start 359.760266 -22.763226)
		(end 359.566718 -22.956774)
		(width 0.12954)
		(layer "F.Cu")
		(net "JTAG_TRC_PCH_PTI<0>")
	)
	(segment
		(start 364.976918 -28.366974)
		(end 364.976918 -28.550362)
		(width 0.12954)
		(layer "F.Cu")
		(net "JTAG_TRC_PCH_PTI<0>")
	)
	(segment
		(start 347.14815 -19.441414)
		(end 356.621842 -19.441414)
		(width 0.12954)
		(layer "F.Cu")
		(net "JTAG_TRC_PCH_PTI<0>")
	)
	(segment
		(start 369.485418 -32.875474)
		(end 369.485418 -33.058862)
		(width 0.12954)
		(layer "F.Cu")
		(net "JTAG_TRC_PCH_PTI<0>")
	)
	(segment
		(start 361.563666 -24.566626)
		(end 361.370118 -24.760174)
		(width 0.12954)
		(layer "F.Cu")
		(net "JTAG_TRC_PCH_PTI<0>")
	)
	(segment
		(start 357.763318 -21.153374)
		(end 357.763318 -21.336762)
		(width 0.12954)
		(layer "F.Cu")
		(net "JTAG_TRC_PCH_PTI<0>")
	)
	(segment
		(start 369.228116 -32.231076)
		(end 369.411504 -32.231076)
		(width 0.12954)
		(layer "F.Cu")
		(net "JTAG_TRC_PCH_PTI<0>")
	)
	(segment
		(start 345.856306 -27.556206)
		(end 346.0369 -27.120088)
		(width 0.12954)
		(layer "F.Cu")
		(net "JTAG_TRC_PCH_PTI<0>")
	)
	(segment
		(start 369.678966 -32.498538)
		(end 369.678966 -32.681926)
		(width 0.12954)
		(layer "F.Cu")
		(net "JTAG_TRC_PCH_PTI<0>")
	)
	(via
		(at 382.138936 -59.578748)
		(size 0.508)
		(drill 0.254)
		(layers "F.Cu" "B.Cu")
		(net "JTAG_TRC_PCH_PTI<0>")
	)
	(segment
		(start 391.641076 -49.018952)
		(end 391.511536 -48.889412)
		(width 0.12954)
		(layer "F.Cu")
		(net "JTAG_TRC_PCH_PTI1_CLK")
	)
	(segment
		(start 392.149076 -48.889412)
		(end 392.019536 -49.018952)
		(width 0.12954)
		(layer "F.Cu")
		(net "JTAG_TRC_PCH_PTI1_CLK")
	)
	(segment
		(start 359.862628 -13.222986)
		(end 390.338818 -43.699176)
		(width 0.12954)
		(layer "F.Cu")
		(net "JTAG_TRC_PCH_PTI1_CLK")
	)
	(segment
		(start 390.338818 -45.98924)
		(end 390.468358 -46.11878)
		(width 0.12954)
		(layer "F.Cu")
		(net "JTAG_TRC_PCH_PTI1_CLK")
	)
	(segment
		(start 390.069578 -48.0314)
		(end 389.47979 -48.621188)
		(width 0.12954)
		(layer "F.Cu")
		(net "JTAG_TRC_PCH_PTI1_CLK")
	)
	(segment
		(start 390.468358 -46.11878)
		(end 392.361674 -46.11878)
		(width 0.12954)
		(layer "F.Cu")
		(net "JTAG_TRC_PCH_PTI1_CLK")
	)
	(segment
		(start 392.149076 -48.16094)
		(end 392.149076 -48.889412)
		(width 0.12954)
		(layer "F.Cu")
		(net "JTAG_TRC_PCH_PTI1_CLK")
	)
	(segment
		(start 337.399884 -38.880288)
		(end 337.400138 -38.880034)
		(width 0.0889)
		(layer "F.Cu")
		(net "JTAG_TRC_PCH_PTI1_CLK")
	)
	(segment
		(start 393.326874 -47.5234)
		(end 393.326874 -47.90186)
		(width 0.12954)
		(layer "F.Cu")
		(net "JTAG_TRC_PCH_PTI1_CLK")
	)
	(segment
		(start 392.361674 -46.11878)
		(end 392.491214 -46.24832)
		(width 0.12954)
		(layer "F.Cu")
		(net "JTAG_TRC_PCH_PTI1_CLK")
	)
	(segment
		(start 389.845804 -49.749964)
		(end 392.034776 -49.749964)
		(width 0.12954)
		(layer "F.Cu")
		(net "JTAG_TRC_PCH_PTI1_CLK")
	)
	(segment
		(start 337.20786 -37.579808)
		(end 337.152234 -37.298884)
		(width 0.0889)
		(layer "F.Cu")
		(net "JTAG_TRC_PCH_PTI1_CLK")
	)
	(segment
		(start 338.233512 -26.341324)
		(end 338.840318 -25.734518)
		(width 0.12954)
		(layer "F.Cu")
		(net "JTAG_TRC_PCH_PTI1_CLK")
	)
	(segment
		(start 391.511536 -48.16094)
		(end 391.381996 -48.0314)
		(width 0.12954)
		(layer "F.Cu")
		(net "JTAG_TRC_PCH_PTI1_CLK")
	)
	(segment
		(start 391.381996 -48.0314)
		(end 390.069578 -48.0314)
		(width 0.12954)
		(layer "F.Cu")
		(net "JTAG_TRC_PCH_PTI1_CLK")
	)
	(segment
		(start 337.227672 -38.345618)
		(end 337.098386 -38.196012)
		(width 0.0889)
		(layer "F.Cu")
		(net "JTAG_TRC_PCH_PTI1_CLK")
	)
	(segment
		(start 337.19897 -37.765482)
		(end 337.20786 -37.579808)
		(width 0.0889)
		(layer "F.Cu")
		(net "JTAG_TRC_PCH_PTI1_CLK")
	)
	(segment
		(start 337.030822 -36.305236)
		(end 337.030822 -30.719522)
		(width 0.0889)
		(layer "F.Cu")
		(net "JTAG_TRC_PCH_PTI1_CLK")
	)
	(segment
		(start 390.338818 -43.699176)
		(end 390.338818 -45.98924)
		(width 0.12954)
		(layer "F.Cu")
		(net "JTAG_TRC_PCH_PTI1_CLK")
	)
	(segment
		(start 338.233512 -28.528772)
		(end 338.233512 -26.341324)
		(width 0.12954)
		(layer "F.Cu")
		(net "JTAG_TRC_PCH_PTI1_CLK")
	)
	(segment
		(start 338.840318 -19.251676)
		(end 344.869008 -13.222986)
		(width 0.12954)
		(layer "F.Cu")
		(net "JTAG_TRC_PCH_PTI1_CLK")
	)
	(segment
		(start 393.197334 -48.0314)
		(end 392.278616 -48.0314)
		(width 0.12954)
		(layer "F.Cu")
		(net "JTAG_TRC_PCH_PTI1_CLK")
	)
	(segment
		(start 390.338818 -47.26432)
		(end 390.468358 -47.39386)
		(width 0.12954)
		(layer "F.Cu")
		(net "JTAG_TRC_PCH_PTI1_CLK")
	)
	(segment
		(start 338.840318 -25.734518)
		(end 338.840318 -19.251676)
		(width 0.12954)
		(layer "F.Cu")
		(net "JTAG_TRC_PCH_PTI1_CLK")
	)
	(segment
		(start 337.152234 -37.298884)
		(end 337.152234 -36.426648)
		(width 0.0889)
		(layer "F.Cu")
		(net "JTAG_TRC_PCH_PTI1_CLK")
	)
	(segment
		(start 389.47979 -49.049432)
		(end 389.47979 -49.38395)
		(width 0.12954)
		(layer "F.Cu")
		(net "JTAG_TRC_PCH_PTI1_CLK")
	)
	(segment
		(start 344.869008 -13.222986)
		(end 359.862628 -13.222986)
		(width 0.12954)
		(layer "F.Cu")
		(net "JTAG_TRC_PCH_PTI1_CLK")
	)
	(segment
		(start 392.491214 -46.24832)
		(end 392.491214 -46.62678)
		(width 0.12954)
		(layer "F.Cu")
		(net "JTAG_TRC_PCH_PTI1_CLK")
	)
	(segment
		(start 391.511536 -48.889412)
		(end 391.511536 -48.16094)
		(width 0.12954)
		(layer "F.Cu")
		(net "JTAG_TRC_PCH_PTI1_CLK")
	)
	(segment
		(start 337.400138 -38.880034)
		(end 337.400138 -38.518084)
		(width 0.0889)
		(layer "F.Cu")
		(net "JTAG_TRC_PCH_PTI1_CLK")
	)
	(segment
		(start 337.313016 -29.449268)
		(end 338.233512 -28.528772)
		(width 0.12954)
		(layer "F.Cu")
		(net "JTAG_TRC_PCH_PTI1_CLK")
	)
	(segment
		(start 392.491214 -46.62678)
		(end 392.361674 -46.75632)
		(width 0.12954)
		(layer "F.Cu")
		(net "JTAG_TRC_PCH_PTI1_CLK")
	)
	(segment
		(start 392.361674 -46.75632)
		(end 390.468358 -46.75632)
		(width 0.12954)
		(layer "F.Cu")
		(net "JTAG_TRC_PCH_PTI1_CLK")
	)
	(segment
		(start 393.326874 -47.90186)
		(end 393.197334 -48.0314)
		(width 0.12954)
		(layer "F.Cu")
		(net "JTAG_TRC_PCH_PTI1_CLK")
	)
	(segment
		(start 337.098386 -37.916612)
		(end 337.19897 -37.765482)
		(width 0.0889)
		(layer "F.Cu")
		(net "JTAG_TRC_PCH_PTI1_CLK")
	)
	(segment
		(start 392.278616 -48.0314)
		(end 392.149076 -48.16094)
		(width 0.12954)
		(layer "F.Cu")
		(net "JTAG_TRC_PCH_PTI1_CLK")
	)
	(segment
		(start 392.019536 -49.018952)
		(end 391.641076 -49.018952)
		(width 0.12954)
		(layer "F.Cu")
		(net "JTAG_TRC_PCH_PTI1_CLK")
	)
	(segment
		(start 390.468358 -47.39386)
		(end 393.197334 -47.39386)
		(width 0.12954)
		(layer "F.Cu")
		(net "JTAG_TRC_PCH_PTI1_CLK")
	)
	(segment
		(start 337.152234 -36.426648)
		(end 337.030822 -36.305236)
		(width 0.0889)
		(layer "F.Cu")
		(net "JTAG_TRC_PCH_PTI1_CLK")
	)
	(segment
		(start 389.47979 -48.621188)
		(end 389.47979 -49.049432)
		(width 0.12954)
		(layer "F.Cu")
		(net "JTAG_TRC_PCH_PTI1_CLK")
	)
	(segment
		(start 390.468358 -46.75632)
		(end 390.338818 -46.88586)
		(width 0.12954)
		(layer "F.Cu")
		(net "JTAG_TRC_PCH_PTI1_CLK")
	)
	(segment
		(start 337.313016 -30.437328)
		(end 337.313016 -29.449268)
		(width 0.12954)
		(layer "F.Cu")
		(net "JTAG_TRC_PCH_PTI1_CLK")
	)
	(segment
		(start 389.47979 -49.38395)
		(end 389.845804 -49.749964)
		(width 0.12954)
		(layer "F.Cu")
		(net "JTAG_TRC_PCH_PTI1_CLK")
	)
	(segment
		(start 337.098386 -38.196012)
		(end 337.098386 -37.916612)
		(width 0.0889)
		(layer "F.Cu")
		(net "JTAG_TRC_PCH_PTI1_CLK")
	)
	(segment
		(start 337.030822 -30.719522)
		(end 337.313016 -30.437328)
		(width 0.12954)
		(layer "F.Cu")
		(net "JTAG_TRC_PCH_PTI1_CLK")
	)
	(segment
		(start 393.197334 -47.39386)
		(end 393.326874 -47.5234)
		(width 0.12954)
		(layer "F.Cu")
		(net "JTAG_TRC_PCH_PTI1_CLK")
	)
	(segment
		(start 390.338818 -46.88586)
		(end 390.338818 -47.26432)
		(width 0.12954)
		(layer "F.Cu")
		(net "JTAG_TRC_PCH_PTI1_CLK")
	)
	(segment
		(start 337.400138 -38.518084)
		(end 337.227672 -38.345618)
		(width 0.0889)
		(layer "F.Cu")
		(net "JTAG_TRC_PCH_PTI1_CLK")
	)
	(via
		(at 389.47979 -49.049432)
		(size 0.508)
		(drill 0.254)
		(layers "F.Cu" "B.Cu")
		(net "JTAG_TRC_PCH_PTI1_CLK")
	)
	(segment
		(start 362.618274 -23.584154)
		(end 362.529374 -23.673054)
		(width 0.12954)
		(layer "F.Cu")
		(net "JTAG_TRC_PCH_PTI0_CLK")
	)
	(segment
		(start 359.373424 -20.700492)
		(end 359.373424 -20.517104)
		(width 0.12954)
		(layer "F.Cu")
		(net "JTAG_TRC_PCH_PTI0_CLK")
	)
	(segment
		(start 362.529374 -23.673054)
		(end 362.345986 -23.673054)
		(width 0.12954)
		(layer "F.Cu")
		(net "JTAG_TRC_PCH_PTI0_CLK")
	)
	(segment
		(start 366.675924 -27.458416)
		(end 366.408462 -27.190954)
		(width 0.12954)
		(layer "F.Cu")
		(net "JTAG_TRC_PCH_PTI0_CLK")
	)
	(segment
		(start 383.196846 -61.249814)
		(end 387.5405 -61.249814)
		(width 0.12954)
		(layer "F.Cu")
		(net "JTAG_TRC_PCH_PTI0_CLK")
	)
	(segment
		(start 341.971376 -34.518346)
		(end 341.971376 -36.34867)
		(width 0.0889)
		(layer "F.Cu")
		(net "JTAG_TRC_PCH_PTI0_CLK")
	)
	(segment
		(start 360.725974 -21.869654)
		(end 360.542586 -21.869654)
		(width 0.12954)
		(layer "F.Cu")
		(net "JTAG_TRC_PCH_PTI0_CLK")
	)
	(segment
		(start 361.716574 -22.682454)
		(end 361.627674 -22.771354)
		(width 0.12954)
		(layer "F.Cu")
		(net "JTAG_TRC_PCH_PTI0_CLK")
	)
	(segment
		(start 365.685324 -27.012392)
		(end 365.685324 -26.829004)
		(width 0.12954)
		(layer "F.Cu")
		(net "JTAG_TRC_PCH_PTI0_CLK")
	)
	(segment
		(start 358.471724 -19.615404)
		(end 358.560624 -19.526504)
		(width 0.12954)
		(layer "F.Cu")
		(net "JTAG_TRC_PCH_PTI0_CLK")
	)
	(segment
		(start 361.444286 -22.771354)
		(end 361.176824 -22.503892)
		(width 0.12954)
		(layer "F.Cu")
		(net "JTAG_TRC_PCH_PTI0_CLK")
	)
	(segment
		(start 380.16688 -57.224168)
		(end 376.17908 -53.236368)
		(width 0.12954)
		(layer "F.Cu")
		(net "JTAG_TRC_PCH_PTI0_CLK")
	)
	(segment
		(start 357.837486 -19.164554)
		(end 357.398066 -18.725134)
		(width 0.12954)
		(layer "F.Cu")
		(net "JTAG_TRC_PCH_PTI0_CLK")
	)
	(segment
		(start 358.560624 -19.526504)
		(end 358.560624 -19.343116)
		(width 0.12954)
		(layer "F.Cu")
		(net "JTAG_TRC_PCH_PTI0_CLK")
	)
	(segment
		(start 362.980224 -24.307292)
		(end 362.980224 -24.123904)
		(width 0.12954)
		(layer "F.Cu")
		(net "JTAG_TRC_PCH_PTI0_CLK")
	)
	(segment
		(start 360.814874 -21.780754)
		(end 360.725974 -21.869654)
		(width 0.12954)
		(layer "F.Cu")
		(net "JTAG_TRC_PCH_PTI0_CLK")
	)
	(segment
		(start 360.096562 -20.879054)
		(end 359.913174 -20.879054)
		(width 0.12954)
		(layer "F.Cu")
		(net "JTAG_TRC_PCH_PTI0_CLK")
	)
	(segment
		(start 341.720424 -38.024054)
		(end 341.720424 -38.106604)
		(width 0.0889)
		(layer "F.Cu")
		(net "JTAG_TRC_PCH_PTI0_CLK")
	)
	(segment
		(start 345.140026 -27.413458)
		(end 345.140026 -29.056584)
		(width 0.12954)
		(layer "F.Cu")
		(net "JTAG_TRC_PCH_PTI0_CLK")
	)
	(segment
		(start 366.225074 -27.190954)
		(end 366.136174 -27.279854)
		(width 0.12954)
		(layer "F.Cu")
		(net "JTAG_TRC_PCH_PTI0_CLK")
	)
	(segment
		(start 362.980224 -24.123904)
		(end 363.069124 -24.035004)
		(width 0.12954)
		(layer "F.Cu")
		(net "JTAG_TRC_PCH_PTI0_CLK")
	)
	(segment
		(start 361.265724 -22.231604)
		(end 361.265724 -22.048216)
		(width 0.12954)
		(layer "F.Cu")
		(net "JTAG_TRC_PCH_PTI0_CLK")
	)
	(segment
		(start 364.783624 -25.927304)
		(end 364.872524 -25.838404)
		(width 0.12954)
		(layer "F.Cu")
		(net "JTAG_TRC_PCH_PTI0_CLK")
	)
	(segment
		(start 362.167424 -23.133304)
		(end 362.167424 -22.949916)
		(width 0.12954)
		(layer "F.Cu")
		(net "JTAG_TRC_PCH_PTI0_CLK")
	)
	(segment
		(start 341.720424 -38.106604)
		(end 341.602822 -38.391084)
		(width 0.0889)
		(layer "F.Cu")
		(net "JTAG_TRC_PCH_PTI0_CLK")
	)
	(segment
		(start 363.247686 -24.574754)
		(end 362.980224 -24.307292)
		(width 0.12954)
		(layer "F.Cu")
		(net "JTAG_TRC_PCH_PTI0_CLK")
	)
	(segment
		(start 341.662258 -37.313616)
		(end 341.625936 -37.43706)
		(width 0.0889)
		(layer "F.Cu")
		(net "JTAG_TRC_PCH_PTI0_CLK")
	)
	(segment
		(start 362.078524 -23.405592)
		(end 362.078524 -23.222204)
		(width 0.12954)
		(layer "F.Cu")
		(net "JTAG_TRC_PCH_PTI0_CLK")
	)
	(segment
		(start 363.970824 -24.936704)
		(end 363.970824 -24.753316)
		(width 0.12954)
		(layer "F.Cu")
		(net "JTAG_TRC_PCH_PTI0_CLK")
	)
	(segment
		(start 361.899962 -22.682454)
		(end 361.716574 -22.682454)
		(width 0.12954)
		(layer "F.Cu")
		(net "JTAG_TRC_PCH_PTI0_CLK")
	)
	(segment
		(start 361.176824 -22.503892)
		(end 361.176824 -22.320504)
		(width 0.12954)
		(layer "F.Cu")
		(net "JTAG_TRC_PCH_PTI0_CLK")
	)
	(segment
		(start 345.140026 -29.056584)
		(end 344.660728 -29.535882)
		(width 0.12954)
		(layer "F.Cu")
		(net "JTAG_TRC_PCH_PTI0_CLK")
	)
	(segment
		(start 359.462324 -20.244816)
		(end 359.194862 -19.977354)
		(width 0.12954)
		(layer "F.Cu")
		(net "JTAG_TRC_PCH_PTI0_CLK")
	)
	(segment
		(start 341.859362 -38.880288)
		(end 342.402414 -38.880288)
		(width 0.0889)
		(layer "F.Cu")
		(net "JTAG_TRC_PCH_PTI0_CLK")
	)
	(segment
		(start 363.970824 -24.753316)
		(end 363.703362 -24.485854)
		(width 0.12954)
		(layer "F.Cu")
		(net "JTAG_TRC_PCH_PTI0_CLK")
	)
	(segment
		(start 365.774224 -26.740104)
		(end 365.774224 -26.556716)
		(width 0.12954)
		(layer "F.Cu")
		(net "JTAG_TRC_PCH_PTI0_CLK")
	)
	(segment
		(start 389.7884 -61.249814)
		(end 392.034776 -61.249814)
		(width 0.12954)
		(layer "F.Cu")
		(net "JTAG_TRC_PCH_PTI0_CLK")
	)
	(segment
		(start 364.332774 -25.476454)
		(end 364.149386 -25.476454)
		(width 0.12954)
		(layer "F.Cu")
		(net "JTAG_TRC_PCH_PTI0_CLK")
	)
	(segment
		(start 358.922574 -20.066254)
		(end 358.739186 -20.066254)
		(width 0.12954)
		(layer "F.Cu")
		(net "JTAG_TRC_PCH_PTI0_CLK")
	)
	(segment
		(start 358.293162 -19.075654)
		(end 358.109774 -19.075654)
		(width 0.12954)
		(layer "F.Cu")
		(net "JTAG_TRC_PCH_PTI0_CLK")
	)
	(segment
		(start 361.176824 -22.320504)
		(end 361.265724 -22.231604)
		(width 0.12954)
		(layer "F.Cu")
		(net "JTAG_TRC_PCH_PTI0_CLK")
	)
	(segment
		(start 365.952786 -27.279854)
		(end 365.685324 -27.012392)
		(width 0.12954)
		(layer "F.Cu")
		(net "JTAG_TRC_PCH_PTI0_CLK")
	)
	(segment
		(start 365.685324 -26.829004)
		(end 365.774224 -26.740104)
		(width 0.12954)
		(layer "F.Cu")
		(net "JTAG_TRC_PCH_PTI0_CLK")
	)
	(segment
		(start 358.020874 -19.164554)
		(end 357.837486 -19.164554)
		(width 0.12954)
		(layer "F.Cu")
		(net "JTAG_TRC_PCH_PTI0_CLK")
	)
	(segment
		(start 365.506762 -26.289254)
		(end 365.323374 -26.289254)
		(width 0.12954)
		(layer "F.Cu")
		(net "JTAG_TRC_PCH_PTI0_CLK")
	)
	(segment
		(start 341.971376 -36.34867)
		(end 341.662258 -36.657788)
		(width 0.0889)
		(layer "F.Cu")
		(net "JTAG_TRC_PCH_PTI0_CLK")
	)
	(segment
		(start 359.824274 -20.967954)
		(end 359.640886 -20.967954)
		(width 0.12954)
		(layer "F.Cu")
		(net "JTAG_TRC_PCH_PTI0_CLK")
	)
	(segment
		(start 341.602822 -38.623748)
		(end 341.859362 -38.880288)
		(width 0.0889)
		(layer "F.Cu")
		(net "JTAG_TRC_PCH_PTI0_CLK")
	)
	(segment
		(start 366.587024 -27.730704)
		(end 366.675924 -27.641804)
		(width 0.12954)
		(layer "F.Cu")
		(net "JTAG_TRC_PCH_PTI0_CLK")
	)
	(segment
		(start 361.265724 -22.048216)
		(end 360.998262 -21.780754)
		(width 0.12954)
		(layer "F.Cu")
		(net "JTAG_TRC_PCH_PTI0_CLK")
	)
	(segment
		(start 359.373424 -20.517104)
		(end 359.462324 -20.428204)
		(width 0.12954)
		(layer "F.Cu")
		(net "JTAG_TRC_PCH_PTI0_CLK")
	)
	(segment
		(start 363.069124 -24.035004)
		(end 363.069124 -23.851616)
		(width 0.12954)
		(layer "F.Cu")
		(net "JTAG_TRC_PCH_PTI0_CLK")
	)
	(segment
		(start 364.872524 -25.655016)
		(end 364.605062 -25.387554)
		(width 0.12954)
		(layer "F.Cu")
		(net "JTAG_TRC_PCH_PTI0_CLK")
	)
	(segment
		(start 364.783624 -26.110692)
		(end 364.783624 -25.927304)
		(width 0.12954)
		(layer "F.Cu")
		(net "JTAG_TRC_PCH_PTI0_CLK")
	)
	(segment
		(start 359.194862 -19.977354)
		(end 359.011474 -19.977354)
		(width 0.12954)
		(layer "F.Cu")
		(net "JTAG_TRC_PCH_PTI0_CLK")
	)
	(segment
		(start 366.587024 -27.914092)
		(end 366.587024 -27.730704)
		(width 0.12954)
		(layer "F.Cu")
		(net "JTAG_TRC_PCH_PTI0_CLK")
	)
	(segment
		(start 364.149386 -25.476454)
		(end 363.881924 -25.208992)
		(width 0.12954)
		(layer "F.Cu")
		(net "JTAG_TRC_PCH_PTI0_CLK")
	)
	(segment
		(start 366.136174 -27.279854)
		(end 365.952786 -27.279854)
		(width 0.12954)
		(layer "F.Cu")
		(net "JTAG_TRC_PCH_PTI0_CLK")
	)
	(segment
		(start 360.275124 -21.418804)
		(end 360.364024 -21.329904)
		(width 0.12954)
		(layer "F.Cu")
		(net "JTAG_TRC_PCH_PTI0_CLK")
	)
	(segment
		(start 358.109774 -19.075654)
		(end 358.020874 -19.164554)
		(width 0.12954)
		(layer "F.Cu")
		(net "JTAG_TRC_PCH_PTI0_CLK")
	)
	(segment
		(start 361.627674 -22.771354)
		(end 361.444286 -22.771354)
		(width 0.12954)
		(layer "F.Cu")
		(net "JTAG_TRC_PCH_PTI0_CLK")
	)
	(segment
		(start 376.17908 -53.236368)
		(end 376.17908 -37.506148)
		(width 0.12954)
		(layer "F.Cu")
		(net "JTAG_TRC_PCH_PTI0_CLK")
	)
	(segment
		(start 364.605062 -25.387554)
		(end 364.421674 -25.387554)
		(width 0.12954)
		(layer "F.Cu")
		(net "JTAG_TRC_PCH_PTI0_CLK")
	)
	(segment
		(start 362.345986 -23.673054)
		(end 362.078524 -23.405592)
		(width 0.12954)
		(layer "F.Cu")
		(net "JTAG_TRC_PCH_PTI0_CLK")
	)
	(segment
		(start 360.364024 -21.146516)
		(end 360.096562 -20.879054)
		(width 0.12954)
		(layer "F.Cu")
		(net "JTAG_TRC_PCH_PTI0_CLK")
	)
	(segment
		(start 342.203278 -34.286444)
		(end 341.971376 -34.518346)
		(width 0.0889)
		(layer "F.Cu")
		(net "JTAG_TRC_PCH_PTI0_CLK")
	)
	(segment
		(start 363.881924 -25.208992)
		(end 363.881924 -25.025604)
		(width 0.12954)
		(layer "F.Cu")
		(net "JTAG_TRC_PCH_PTI0_CLK")
	)
	(segment
		(start 341.662258 -36.657788)
		(end 341.662258 -37.313616)
		(width 0.0889)
		(layer "F.Cu")
		(net "JTAG_TRC_PCH_PTI0_CLK")
	)
	(segment
		(start 358.560624 -19.343116)
		(end 358.293162 -19.075654)
		(width 0.12954)
		(layer "F.Cu")
		(net "JTAG_TRC_PCH_PTI0_CLK")
	)
	(segment
		(start 362.801662 -23.584154)
		(end 362.618274 -23.584154)
		(width 0.12954)
		(layer "F.Cu")
		(net "JTAG_TRC_PCH_PTI0_CLK")
	)
	(segment
		(start 341.625936 -37.43706)
		(end 341.625936 -37.805614)
		(width 0.0889)
		(layer "F.Cu")
		(net "JTAG_TRC_PCH_PTI0_CLK")
	)
	(segment
		(start 364.421674 -25.387554)
		(end 364.332774 -25.476454)
		(width 0.12954)
		(layer "F.Cu")
		(net "JTAG_TRC_PCH_PTI0_CLK")
	)
	(segment
		(start 359.011474 -19.977354)
		(end 358.922574 -20.066254)
		(width 0.12954)
		(layer "F.Cu")
		(net "JTAG_TRC_PCH_PTI0_CLK")
	)
	(segment
		(start 359.640886 -20.967954)
		(end 359.373424 -20.700492)
		(width 0.12954)
		(layer "F.Cu")
		(net "JTAG_TRC_PCH_PTI0_CLK")
	)
	(segment
		(start 360.542586 -21.869654)
		(end 360.275124 -21.602192)
		(width 0.12954)
		(layer "F.Cu")
		(net "JTAG_TRC_PCH_PTI0_CLK")
	)
	(segment
		(start 344.660728 -31.828994)
		(end 342.203278 -34.286444)
		(width 0.12954)
		(layer "F.Cu")
		(net "JTAG_TRC_PCH_PTI0_CLK")
	)
	(segment
		(start 366.675924 -27.641804)
		(end 366.675924 -27.458416)
		(width 0.12954)
		(layer "F.Cu")
		(net "JTAG_TRC_PCH_PTI0_CLK")
	)
	(segment
		(start 360.364024 -21.329904)
		(end 360.364024 -21.146516)
		(width 0.12954)
		(layer "F.Cu")
		(net "JTAG_TRC_PCH_PTI0_CLK")
	)
	(segment
		(start 360.998262 -21.780754)
		(end 360.814874 -21.780754)
		(width 0.12954)
		(layer "F.Cu")
		(net "JTAG_TRC_PCH_PTI0_CLK")
	)
	(segment
		(start 359.462324 -20.428204)
		(end 359.462324 -20.244816)
		(width 0.12954)
		(layer "F.Cu")
		(net "JTAG_TRC_PCH_PTI0_CLK")
	)
	(segment
		(start 345.316302 -20.259802)
		(end 345.316302 -26.987754)
		(width 0.12954)
		(layer "F.Cu")
		(net "JTAG_TRC_PCH_PTI0_CLK")
	)
	(segment
		(start 341.602822 -38.391084)
		(end 341.602822 -38.623748)
		(width 0.0889)
		(layer "F.Cu")
		(net "JTAG_TRC_PCH_PTI0_CLK")
	)
	(segment
		(start 362.078524 -23.222204)
		(end 362.167424 -23.133304)
		(width 0.12954)
		(layer "F.Cu")
		(net "JTAG_TRC_PCH_PTI0_CLK")
	)
	(segment
		(start 376.17908 -37.506148)
		(end 366.587024 -27.914092)
		(width 0.12954)
		(layer "F.Cu")
		(net "JTAG_TRC_PCH_PTI0_CLK")
	)
	(segment
		(start 359.913174 -20.879054)
		(end 359.824274 -20.967954)
		(width 0.12954)
		(layer "F.Cu")
		(net "JTAG_TRC_PCH_PTI0_CLK")
	)
	(segment
		(start 365.051086 -26.378154)
		(end 364.783624 -26.110692)
		(width 0.12954)
		(layer "F.Cu")
		(net "JTAG_TRC_PCH_PTI0_CLK")
	)
	(segment
		(start 360.275124 -21.602192)
		(end 360.275124 -21.418804)
		(width 0.12954)
		(layer "F.Cu")
		(net "JTAG_TRC_PCH_PTI0_CLK")
	)
	(segment
		(start 364.872524 -25.838404)
		(end 364.872524 -25.655016)
		(width 0.12954)
		(layer "F.Cu")
		(net "JTAG_TRC_PCH_PTI0_CLK")
	)
	(segment
		(start 387.5405 -61.249814)
		(end 387.843014 -61.552328)
		(width 0.12954)
		(layer "F.Cu")
		(net "JTAG_TRC_PCH_PTI0_CLK")
	)
	(segment
		(start 341.625936 -37.805614)
		(end 341.720424 -38.024054)
		(width 0.0889)
		(layer "F.Cu")
		(net "JTAG_TRC_PCH_PTI0_CLK")
	)
	(segment
		(start 365.323374 -26.289254)
		(end 365.234474 -26.378154)
		(width 0.12954)
		(layer "F.Cu")
		(net "JTAG_TRC_PCH_PTI0_CLK")
	)
	(segment
		(start 363.431074 -24.574754)
		(end 363.247686 -24.574754)
		(width 0.12954)
		(layer "F.Cu")
		(net "JTAG_TRC_PCH_PTI0_CLK")
	)
	(segment
		(start 363.703362 -24.485854)
		(end 363.519974 -24.485854)
		(width 0.12954)
		(layer "F.Cu")
		(net "JTAG_TRC_PCH_PTI0_CLK")
	)
	(segment
		(start 363.881924 -25.025604)
		(end 363.970824 -24.936704)
		(width 0.12954)
		(layer "F.Cu")
		(net "JTAG_TRC_PCH_PTI0_CLK")
	)
	(segment
		(start 389.485886 -61.552328)
		(end 389.7884 -61.249814)
		(width 0.12954)
		(layer "F.Cu")
		(net "JTAG_TRC_PCH_PTI0_CLK")
	)
	(segment
		(start 362.167424 -22.949916)
		(end 361.899962 -22.682454)
		(width 0.12954)
		(layer "F.Cu")
		(net "JTAG_TRC_PCH_PTI0_CLK")
	)
	(segment
		(start 344.660728 -29.535882)
		(end 344.660728 -31.828994)
		(width 0.12954)
		(layer "F.Cu")
		(net "JTAG_TRC_PCH_PTI0_CLK")
	)
	(segment
		(start 345.316302 -26.987754)
		(end 345.140026 -27.413458)
		(width 0.12954)
		(layer "F.Cu")
		(net "JTAG_TRC_PCH_PTI0_CLK")
	)
	(segment
		(start 365.234474 -26.378154)
		(end 365.051086 -26.378154)
		(width 0.12954)
		(layer "F.Cu")
		(net "JTAG_TRC_PCH_PTI0_CLK")
	)
	(segment
		(start 358.471724 -19.798792)
		(end 358.471724 -19.615404)
		(width 0.12954)
		(layer "F.Cu")
		(net "JTAG_TRC_PCH_PTI0_CLK")
	)
	(segment
		(start 357.398066 -18.725134)
		(end 346.85097 -18.725134)
		(width 0.12954)
		(layer "F.Cu")
		(net "JTAG_TRC_PCH_PTI0_CLK")
	)
	(segment
		(start 363.519974 -24.485854)
		(end 363.431074 -24.574754)
		(width 0.12954)
		(layer "F.Cu")
		(net "JTAG_TRC_PCH_PTI0_CLK")
	)
	(segment
		(start 366.408462 -27.190954)
		(end 366.225074 -27.190954)
		(width 0.12954)
		(layer "F.Cu")
		(net "JTAG_TRC_PCH_PTI0_CLK")
	)
	(segment
		(start 365.774224 -26.556716)
		(end 365.506762 -26.289254)
		(width 0.12954)
		(layer "F.Cu")
		(net "JTAG_TRC_PCH_PTI0_CLK")
	)
	(segment
		(start 382.6764 -60.729368)
		(end 383.196846 -61.249814)
		(width 0.12954)
		(layer "F.Cu")
		(net "JTAG_TRC_PCH_PTI0_CLK")
	)
	(segment
		(start 358.739186 -20.066254)
		(end 358.471724 -19.798792)
		(width 0.12954)
		(layer "F.Cu")
		(net "JTAG_TRC_PCH_PTI0_CLK")
	)
	(segment
		(start 387.843014 -61.552328)
		(end 389.485886 -61.552328)
		(width 0.12954)
		(layer "F.Cu")
		(net "JTAG_TRC_PCH_PTI0_CLK")
	)
	(segment
		(start 346.85097 -18.725134)
		(end 345.316302 -20.259802)
		(width 0.12954)
		(layer "F.Cu")
		(net "JTAG_TRC_PCH_PTI0_CLK")
	)
	(segment
		(start 363.069124 -23.851616)
		(end 362.801662 -23.584154)
		(width 0.12954)
		(layer "F.Cu")
		(net "JTAG_TRC_PCH_PTI0_CLK")
	)
	(via
		(at 382.6764 -60.729368)
		(size 0.508)
		(drill 0.254)
		(layers "F.Cu" "B.Cu")
		(net "JTAG_TRC_PCH_PTI0_CLK")
	)
	(via
		(at 380.16688 -57.224168)
		(size 0.508)
		(drill 0.254)
		(layers "F.Cu" "B.Cu")
		(net "JTAG_TRC_PCH_PTI0_CLK")
	)
	(segment
		(start 381.234442 -59.28741)
		(end 381.051054 -59.28741)
		(width 0.12954)
		(layer "B.Cu")
		(net "JTAG_TRC_PCH_PTI0_CLK")
	)
	(segment
		(start 381.03048 -58.087768)
		(end 380.16688 -57.224168)
		(width 0.12954)
		(layer "B.Cu")
		(net "JTAG_TRC_PCH_PTI0_CLK")
	)
	(segment
		(start 380.577344 -58.85942)
		(end 381.03048 -58.406284)
		(width 0.12954)
		(layer "B.Cu")
		(net "JTAG_TRC_PCH_PTI0_CLK")
	)
	(segment
		(start 379.943614 -59.31027)
		(end 379.370082 -58.736484)
		(width 0.12954)
		(layer "B.Cu")
		(net "JTAG_TRC_PCH_PTI0_CLK")
	)
	(segment
		(start 380.679198 -61.279278)
		(end 380.411736 -61.011816)
		(width 0.12954)
		(layer "B.Cu")
		(net "JTAG_TRC_PCH_PTI0_CLK")
	)
	(segment
		(start 379.638052 -58.285634)
		(end 379.820932 -58.285634)
		(width 0.12954)
		(layer "B.Cu")
		(net "JTAG_TRC_PCH_PTI0_CLK")
	)
	(segment
		(start 381.051054 -59.28741)
		(end 379.960886 -60.377578)
		(width 0.12954)
		(layer "B.Cu")
		(net "JTAG_TRC_PCH_PTI0_CLK")
	)
	(segment
		(start 379.510036 -59.926728)
		(end 379.943614 -59.49315)
		(width 0.12954)
		(layer "B.Cu")
		(net "JTAG_TRC_PCH_PTI0_CLK")
	)
	(segment
		(start 381.501904 -59.554872)
		(end 381.234442 -59.28741)
		(width 0.12954)
		(layer "B.Cu")
		(net "JTAG_TRC_PCH_PTI0_CLK")
	)
	(segment
		(start 379.370082 -58.736484)
		(end 379.370082 -58.553604)
		(width 0.12954)
		(layer "B.Cu")
		(net "JTAG_TRC_PCH_PTI0_CLK")
	)
	(segment
		(start 382.136142 -60.18911)
		(end 381.952754 -60.18911)
		(width 0.12954)
		(layer "B.Cu")
		(net "JTAG_TRC_PCH_PTI0_CLK")
	)
	(segment
		(start 379.960886 -60.377578)
		(end 379.777498 -60.377578)
		(width 0.12954)
		(layer "B.Cu")
		(net "JTAG_TRC_PCH_PTI0_CLK")
	)
	(segment
		(start 380.394464 -58.85942)
		(end 380.577344 -58.85942)
		(width 0.12954)
		(layer "B.Cu")
		(net "JTAG_TRC_PCH_PTI0_CLK")
	)
	(segment
		(start 382.6764 -60.729368)
		(end 382.136142 -60.18911)
		(width 0.12954)
		(layer "B.Cu")
		(net "JTAG_TRC_PCH_PTI0_CLK")
	)
	(segment
		(start 379.370082 -58.553604)
		(end 379.638052 -58.285634)
		(width 0.12954)
		(layer "B.Cu")
		(net "JTAG_TRC_PCH_PTI0_CLK")
	)
	(segment
		(start 379.510036 -60.110116)
		(end 379.510036 -59.926728)
		(width 0.12954)
		(layer "B.Cu")
		(net "JTAG_TRC_PCH_PTI0_CLK")
	)
	(segment
		(start 380.862586 -61.279278)
		(end 380.679198 -61.279278)
		(width 0.12954)
		(layer "B.Cu")
		(net "JTAG_TRC_PCH_PTI0_CLK")
	)
	(segment
		(start 380.411736 -61.011816)
		(end 380.411736 -60.828428)
		(width 0.12954)
		(layer "B.Cu")
		(net "JTAG_TRC_PCH_PTI0_CLK")
	)
	(segment
		(start 380.411736 -60.828428)
		(end 381.501904 -59.73826)
		(width 0.12954)
		(layer "B.Cu")
		(net "JTAG_TRC_PCH_PTI0_CLK")
	)
	(segment
		(start 379.943614 -59.49315)
		(end 379.943614 -59.31027)
		(width 0.12954)
		(layer "B.Cu")
		(net "JTAG_TRC_PCH_PTI0_CLK")
	)
	(segment
		(start 381.03048 -58.406284)
		(end 381.03048 -58.087768)
		(width 0.12954)
		(layer "B.Cu")
		(net "JTAG_TRC_PCH_PTI0_CLK")
	)
	(segment
		(start 381.952754 -60.18911)
		(end 380.862586 -61.279278)
		(width 0.12954)
		(layer "B.Cu")
		(net "JTAG_TRC_PCH_PTI0_CLK")
	)
	(segment
		(start 379.820932 -58.285634)
		(end 380.394464 -58.85942)
		(width 0.12954)
		(layer "B.Cu")
		(net "JTAG_TRC_PCH_PTI0_CLK")
	)
	(segment
		(start 379.777498 -60.377578)
		(end 379.510036 -60.110116)
		(width 0.12954)
		(layer "B.Cu")
		(net "JTAG_TRC_PCH_PTI0_CLK")
	)
	(segment
		(start 381.501904 -59.73826)
		(end 381.501904 -59.554872)
		(width 0.12954)
		(layer "B.Cu")
		(net "JTAG_TRC_PCH_PTI0_CLK")
	)
	(segment
		(start 403.546056 -65.085976)
		(end 403.546056 -64.045084)
		(width 0.12954)
		(layer "F.Cu")
		(net "JTAG_RST_DBP_RST_CO_N")
	)
	(segment
		(start 399.476722 -63.24981)
		(end 397.765016 -63.24981)
		(width 0.12954)
		(layer "F.Cu")
		(net "JTAG_RST_DBP_RST_CO_N")
	)
	(segment
		(start 403.546056 -64.045084)
		(end 403.540976 -64.040004)
		(width 0.12954)
		(layer "F.Cu")
		(net "JTAG_RST_DBP_RST_CO_N")
	)
	(segment
		(start 399.98904 -63.762128)
		(end 399.476722 -63.24981)
		(width 0.12954)
		(layer "F.Cu")
		(net "JTAG_RST_DBP_RST_CO_N")
	)
	(segment
		(start 403.2631 -63.762128)
		(end 399.98904 -63.762128)
		(width 0.12954)
		(layer "F.Cu")
		(net "JTAG_RST_DBP_RST_CO_N")
	)
	(segment
		(start 403.540976 -64.040004)
		(end 403.2631 -63.762128)
		(width 0.12954)
		(layer "F.Cu")
		(net "JTAG_RST_DBP_RST_CO_N")
	)
	(via
		(at 399.98904 -63.762128)
		(size 0.508)
		(drill 0.254)
		(layers "F.Cu" "B.Cu")
		(net "JTAG_RST_DBP_RST_CO_N")
	)
	(segment
		(start 395.67104 -54.557168)
		(end 395.97838 -54.249828)
		(width 0.12954)
		(layer "F.Cu")
		(net "JTAG_RST_DBP_RSMRST_N")
	)
	(segment
		(start 395.97838 -54.249828)
		(end 397.765016 -54.249828)
		(width 0.12954)
		(layer "F.Cu")
		(net "JTAG_RST_DBP_RSMRST_N")
	)
	(via
		(at 395.67104 -54.557168)
		(size 0.508)
		(drill 0.254)
		(layers "F.Cu" "B.Cu")
		(net "JTAG_RST_DBP_RSMRST_N")
	)
	(segment
		(start 395.67104 -54.557168)
		(end 397.74622 -54.557168)
		(width 0.12954)
		(layer "B.Cu")
		(net "JTAG_RST_DBP_RSMRST_N")
	)
	(segment
		(start 399.58137 -52.722018)
		(end 403.606762 -52.722018)
		(width 0.12954)
		(layer "B.Cu")
		(net "JTAG_RST_DBP_RSMRST_N")
	)
	(segment
		(start 397.74622 -54.557168)
		(end 399.58137 -52.722018)
		(width 0.12954)
		(layer "B.Cu")
		(net "JTAG_RST_DBP_RSMRST_N")
	)
	(segment
		(start 351.50806 -126.792228)
		(end 352.4504 -126.792228)
		(width 0.12954)
		(layer "F.Cu")
		(net "JTAG_QS_MUX_GTL_TDI")
	)
	(segment
		(start 218.870276 -150.14194)
		(end 219.612464 -150.884128)
		(width 0.12954)
		(layer "F.Cu")
		(net "JTAG_QS_MUX_GTL_TDI")
	)
	(segment
		(start 250.36526 -150.884128)
		(end 255.39446 -145.854928)
		(width 0.12954)
		(layer "F.Cu")
		(net "JTAG_QS_MUX_GTL_TDI")
	)
	(segment
		(start 350.78924 -127.511048)
		(end 351.50806 -126.792228)
		(width 0.12954)
		(layer "F.Cu")
		(net "JTAG_QS_MUX_GTL_TDI")
	)
	(segment
		(start 219.612464 -150.884128)
		(end 250.36526 -150.884128)
		(width 0.12954)
		(layer "F.Cu")
		(net "JTAG_QS_MUX_GTL_TDI")
	)
	(segment
		(start 291.29736 -145.854928)
		(end 309.64124 -127.511048)
		(width 0.12954)
		(layer "F.Cu")
		(net "JTAG_QS_MUX_GTL_TDI")
	)
	(segment
		(start 367.919254 -59.370468)
		(end 365.782606 -57.23382)
		(width 0.12954)
		(layer "F.Cu")
		(net "JTAG_QS_MUX_GTL_TDI")
	)
	(segment
		(start 365.782606 -57.23382)
		(end 364.841282 -57.23382)
		(width 0.12954)
		(layer "F.Cu")
		(net "JTAG_QS_MUX_GTL_TDI")
	)
	(segment
		(start 368.07394 -59.370468)
		(end 367.919254 -59.370468)
		(width 0.12954)
		(layer "F.Cu")
		(net "JTAG_QS_MUX_GTL_TDI")
	)
	(segment
		(start 309.64124 -127.511048)
		(end 350.78924 -127.511048)
		(width 0.12954)
		(layer "F.Cu")
		(net "JTAG_QS_MUX_GTL_TDI")
	)
	(segment
		(start 255.39446 -145.854928)
		(end 291.29736 -145.854928)
		(width 0.12954)
		(layer "F.Cu")
		(net "JTAG_QS_MUX_GTL_TDI")
	)
	(segment
		(start 211.955888 -150.14194)
		(end 218.870276 -150.14194)
		(width 0.12954)
		(layer "F.Cu")
		(net "JTAG_QS_MUX_GTL_TDI")
	)
	(segment
		(start 211.25307 -150.844758)
		(end 211.955888 -150.14194)
		(width 0.12954)
		(layer "F.Cu")
		(net "JTAG_QS_MUX_GTL_TDI")
	)
	(via
		(at 203.092558 -193.29019)
		(size 0.508)
		(drill 0.254)
		(layers "F.Cu" "B.Cu")
		(net "JTAG_QS_MUX_GTL_TDI")
	)
	(via
		(at 368.07394 -59.370468)
		(size 0.508)
		(drill 0.254)
		(layers "F.Cu" "B.Cu")
		(net "JTAG_QS_MUX_GTL_TDI")
	)
	(via
		(at 352.4504 -126.792228)
		(size 0.508)
		(drill 0.254)
		(layers "F.Cu" "B.Cu")
		(net "JTAG_QS_MUX_GTL_TDI")
	)
	(via
		(at 211.25307 -150.844758)
		(size 0.508)
		(drill 0.254)
		(layers "F.Cu" "B.Cu")
		(net "JTAG_QS_MUX_GTL_TDI")
	)
	(segment
		(start 203.86548 -191.861948)
		(end 205.6638 -191.861948)
		(width 0.12954)
		(layer "B.Cu")
		(net "JTAG_QS_MUX_GTL_TDI")
	)
	(segment
		(start 203.092558 -192.63487)
		(end 203.86548 -191.861948)
		(width 0.12954)
		(layer "B.Cu")
		(net "JTAG_QS_MUX_GTL_TDI")
	)
	(segment
		(start 205.6638 -191.861948)
		(end 205.9559 -192.154048)
		(width 0.12954)
		(layer "B.Cu")
		(net "JTAG_QS_MUX_GTL_TDI")
	)
	(segment
		(start 203.092558 -193.29019)
		(end 203.092558 -192.63487)
		(width 0.12954)
		(layer "B.Cu")
		(net "JTAG_QS_MUX_GTL_TDI")
	)
	(segment
		(start 205.9559 -192.154048)
		(end 205.9559 -192.724024)
		(width 0.12954)
		(layer "B.Cu")
		(net "JTAG_QS_MUX_GTL_TDI")
	)
	(segment
		(start 368.07394 -86.617048)
		(end 369.93068 -88.473788)
		(width 0.127)
		(layer "In2.Cu")
		(net "JTAG_QS_MUX_GTL_TDI")
	)
	(segment
		(start 366.03686 -109.057948)
		(end 355.172264 -126.193804)
		(width 0.127)
		(layer "In2.Cu")
		(net "JTAG_QS_MUX_GTL_TDI")
	)
	(segment
		(start 366.03686 -102.311708)
		(end 366.03686 -109.057948)
		(width 0.127)
		(layer "In2.Cu")
		(net "JTAG_QS_MUX_GTL_TDI")
	)
	(segment
		(start 371.2972 -94.071948)
		(end 371.2972 -94.402148)
		(width 0.127)
		(layer "In2.Cu")
		(net "JTAG_QS_MUX_GTL_TDI")
	)
	(segment
		(start 210.74888 -164.556948)
		(end 210.74888 -151.348948)
		(width 0.127)
		(layer "In2.Cu")
		(net "JTAG_QS_MUX_GTL_TDI")
	)
	(segment
		(start 204.768958 -187.95111)
		(end 210.483958 -182.23611)
		(width 0.127)
		(layer "In2.Cu")
		(net "JTAG_QS_MUX_GTL_TDI")
	)
	(segment
		(start 372.6434 -90.480388)
		(end 372.6434 -92.725748)
		(width 0.127)
		(layer "In2.Cu")
		(net "JTAG_QS_MUX_GTL_TDI")
	)
	(segment
		(start 354.06711 -127.298958)
		(end 352.95713 -127.298958)
		(width 0.127)
		(layer "In2.Cu")
		(net "JTAG_QS_MUX_GTL_TDI")
	)
	(segment
		(start 352.95713 -127.298958)
		(end 352.4504 -126.792228)
		(width 0.127)
		(layer "In2.Cu")
		(net "JTAG_QS_MUX_GTL_TDI")
	)
	(segment
		(start 368.07394 -59.370468)
		(end 368.07394 -86.617048)
		(width 0.127)
		(layer "In2.Cu")
		(net "JTAG_QS_MUX_GTL_TDI")
	)
	(segment
		(start 371.2972 -94.402148)
		(end 370.90858 -94.790768)
		(width 0.127)
		(layer "In2.Cu")
		(net "JTAG_QS_MUX_GTL_TDI")
	)
	(segment
		(start 370.90858 -97.439988)
		(end 366.03686 -102.311708)
		(width 0.127)
		(layer "In2.Cu")
		(net "JTAG_QS_MUX_GTL_TDI")
	)
	(segment
		(start 210.483958 -164.82187)
		(end 210.74888 -164.556948)
		(width 0.127)
		(layer "In2.Cu")
		(net "JTAG_QS_MUX_GTL_TDI")
	)
	(segment
		(start 355.172264 -126.193804)
		(end 354.06711 -127.298958)
		(width 0.127)
		(layer "In2.Cu")
		(net "JTAG_QS_MUX_GTL_TDI")
	)
	(segment
		(start 369.93068 -88.473788)
		(end 370.6368 -88.473788)
		(width 0.127)
		(layer "In2.Cu")
		(net "JTAG_QS_MUX_GTL_TDI")
	)
	(segment
		(start 370.6368 -88.473788)
		(end 372.6434 -90.480388)
		(width 0.127)
		(layer "In2.Cu")
		(net "JTAG_QS_MUX_GTL_TDI")
	)
	(segment
		(start 370.90858 -94.790768)
		(end 370.90858 -97.439988)
		(width 0.127)
		(layer "In2.Cu")
		(net "JTAG_QS_MUX_GTL_TDI")
	)
	(segment
		(start 203.092558 -193.29019)
		(end 203.092558 -191.998092)
		(width 0.127)
		(layer "In2.Cu")
		(net "JTAG_QS_MUX_GTL_TDI")
	)
	(segment
		(start 372.6434 -92.725748)
		(end 371.2972 -94.071948)
		(width 0.127)
		(layer "In2.Cu")
		(net "JTAG_QS_MUX_GTL_TDI")
	)
	(segment
		(start 210.74888 -151.348948)
		(end 211.25307 -150.844758)
		(width 0.127)
		(layer "In2.Cu")
		(net "JTAG_QS_MUX_GTL_TDI")
	)
	(segment
		(start 203.092558 -191.998092)
		(end 204.768958 -187.95111)
		(width 0.127)
		(layer "In2.Cu")
		(net "JTAG_QS_MUX_GTL_TDI")
	)
	(segment
		(start 210.483958 -182.23611)
		(end 210.483958 -164.82187)
		(width 0.127)
		(layer "In2.Cu")
		(net "JTAG_QS_MUX_GTL_TDI")
	)
	(segment
		(start 121.24055 -65.750948)
		(end 120.714008 -66.27749)
		(width 0.12954)
		(layer "F.Cu")
		(net "JTAG_PLD_TMS_R")
	)
	(segment
		(start 171.755562 -112.175544)
		(end 171.355512 -111.775494)
		(width 0.12954)
		(layer "F.Cu")
		(net "JTAG_PLD_TMS_R")
	)
	(segment
		(start 121.539 -65.750948)
		(end 121.24055 -65.750948)
		(width 0.12954)
		(layer "F.Cu")
		(net "JTAG_PLD_TMS_R")
	)
	(via
		(at 158.04388 -113.756948)
		(size 0.508)
		(drill 0.254)
		(layers "F.Cu" "B.Cu")
		(net "JTAG_PLD_TMS_R")
	)
	(via
		(at 121.539 -65.750948)
		(size 0.508)
		(drill 0.254)
		(layers "F.Cu" "B.Cu")
		(net "JTAG_PLD_TMS_R")
	)
	(via
		(at 171.355512 -111.775494)
		(size 0.4572)
		(drill 0.254)
		(layers "F.Cu" "B.Cu")
		(net "JTAG_PLD_TMS_R")
	)
	(segment
		(start 115.71224 -74.734928)
		(end 117.40896 -73.038208)
		(width 0.127)
		(layer "In2.Cu")
		(net "JTAG_PLD_TMS_R")
	)
	(segment
		(start 151.228806 -107.329986)
		(end 150.53564 -106.63682)
		(width 0.127)
		(layer "In2.Cu")
		(net "JTAG_PLD_TMS_R")
	)
	(segment
		(start 151.228806 -109.431074)
		(end 151.228806 -107.329986)
		(width 0.127)
		(layer "In2.Cu")
		(net "JTAG_PLD_TMS_R")
	)
	(segment
		(start 120.714008 -72.33158)
		(end 120.714008 -66.57594)
		(width 0.127)
		(layer "In2.Cu")
		(net "JTAG_PLD_TMS_R")
	)
	(segment
		(start 120.188736 -82.626708)
		(end 115.71224 -78.150212)
		(width 0.127)
		(layer "In2.Cu")
		(net "JTAG_PLD_TMS_R")
	)
	(segment
		(start 144.919192 -82.626708)
		(end 120.188736 -82.626708)
		(width 0.127)
		(layer "In2.Cu")
		(net "JTAG_PLD_TMS_R")
	)
	(segment
		(start 120.00738 -73.038208)
		(end 120.714008 -72.33158)
		(width 0.127)
		(layer "In2.Cu")
		(net "JTAG_PLD_TMS_R")
	)
	(segment
		(start 154.96032 -113.162588)
		(end 151.228806 -109.431074)
		(width 0.127)
		(layer "In2.Cu")
		(net "JTAG_PLD_TMS_R")
	)
	(segment
		(start 146.28114 -92.71)
		(end 146.28114 -83.988656)
		(width 0.127)
		(layer "In2.Cu")
		(net "JTAG_PLD_TMS_R")
	)
	(segment
		(start 158.04388 -113.756948)
		(end 157.19552 -113.756948)
		(width 0.127)
		(layer "In2.Cu")
		(net "JTAG_PLD_TMS_R")
	)
	(segment
		(start 146.28114 -83.988656)
		(end 144.919192 -82.626708)
		(width 0.127)
		(layer "In2.Cu")
		(net "JTAG_PLD_TMS_R")
	)
	(segment
		(start 150.53564 -96.9645)
		(end 146.28114 -92.71)
		(width 0.127)
		(layer "In2.Cu")
		(net "JTAG_PLD_TMS_R")
	)
	(segment
		(start 150.53564 -106.63682)
		(end 150.53564 -96.9645)
		(width 0.127)
		(layer "In2.Cu")
		(net "JTAG_PLD_TMS_R")
	)
	(segment
		(start 120.714008 -66.57594)
		(end 121.539 -65.750948)
		(width 0.127)
		(layer "In2.Cu")
		(net "JTAG_PLD_TMS_R")
	)
	(segment
		(start 117.40896 -73.038208)
		(end 120.00738 -73.038208)
		(width 0.127)
		(layer "In2.Cu")
		(net "JTAG_PLD_TMS_R")
	)
	(segment
		(start 157.19552 -113.756948)
		(end 156.60116 -113.162588)
		(width 0.127)
		(layer "In2.Cu")
		(net "JTAG_PLD_TMS_R")
	)
	(segment
		(start 156.60116 -113.162588)
		(end 154.96032 -113.162588)
		(width 0.127)
		(layer "In2.Cu")
		(net "JTAG_PLD_TMS_R")
	)
	(segment
		(start 115.71224 -78.150212)
		(end 115.71224 -74.734928)
		(width 0.127)
		(layer "In2.Cu")
		(net "JTAG_PLD_TMS_R")
	)
	(segment
		(start 164.04336 -112.819688)
		(end 161.48558 -112.819688)
		(width 0.127)
		(layer "In6.Cu")
		(net "JTAG_PLD_TMS_R")
	)
	(segment
		(start 159.941768 -114.3635)
		(end 158.650432 -114.3635)
		(width 0.127)
		(layer "In6.Cu")
		(net "JTAG_PLD_TMS_R")
	)
	(segment
		(start 169.351706 -111.775494)
		(end 168.523666 -112.603534)
		(width 0.127)
		(layer "In6.Cu")
		(net "JTAG_PLD_TMS_R")
	)
	(segment
		(start 171.355512 -111.775494)
		(end 169.351706 -111.775494)
		(width 0.127)
		(layer "In6.Cu")
		(net "JTAG_PLD_TMS_R")
	)
	(segment
		(start 161.48558 -112.819688)
		(end 159.941768 -114.3635)
		(width 0.127)
		(layer "In6.Cu")
		(net "JTAG_PLD_TMS_R")
	)
	(segment
		(start 168.523666 -112.603534)
		(end 164.259514 -112.603534)
		(width 0.127)
		(layer "In6.Cu")
		(net "JTAG_PLD_TMS_R")
	)
	(segment
		(start 164.259514 -112.603534)
		(end 164.04336 -112.819688)
		(width 0.127)
		(layer "In6.Cu")
		(net "JTAG_PLD_TMS_R")
	)
	(segment
		(start 158.650432 -114.3635)
		(end 158.04388 -113.756948)
		(width 0.127)
		(layer "In6.Cu")
		(net "JTAG_PLD_TMS_R")
	)
	(segment
		(start 131.471924 -66.519552)
		(end 131.014216 -66.519552)
		(width 0.12954)
		(layer "F.Cu")
		(net "JTAG_PLD_TDO_R")
	)
	(segment
		(start 130.80238 -71.431404)
		(end 130.80238 -68.679568)
		(width 0.12954)
		(layer "F.Cu")
		(net "JTAG_PLD_TDO_R")
	)
	(segment
		(start 130.80238 -68.679568)
		(end 131.72186 -67.760088)
		(width 0.12954)
		(layer "F.Cu")
		(net "JTAG_PLD_TDO_R")
	)
	(segment
		(start 131.72186 -66.769488)
		(end 131.471924 -66.519552)
		(width 0.12954)
		(layer "F.Cu")
		(net "JTAG_PLD_TDO_R")
	)
	(segment
		(start 130.671824 -78.593188)
		(end 130.118866 -78.04023)
		(width 0.12954)
		(layer "F.Cu")
		(net "JTAG_PLD_TDO_R")
	)
	(segment
		(start 136.25068 -78.593188)
		(end 130.671824 -78.593188)
		(width 0.12954)
		(layer "F.Cu")
		(net "JTAG_PLD_TDO_R")
	)
	(segment
		(start 173.355762 -110.575344)
		(end 172.955712 -110.175294)
		(width 0.12954)
		(layer "F.Cu")
		(net "JTAG_PLD_TDO_R")
	)
	(segment
		(start 130.118866 -72.114918)
		(end 130.80238 -71.431404)
		(width 0.12954)
		(layer "F.Cu")
		(net "JTAG_PLD_TDO_R")
	)
	(segment
		(start 131.72186 -67.760088)
		(end 131.72186 -66.769488)
		(width 0.12954)
		(layer "F.Cu")
		(net "JTAG_PLD_TDO_R")
	)
	(segment
		(start 130.118866 -78.04023)
		(end 130.118866 -72.114918)
		(width 0.12954)
		(layer "F.Cu")
		(net "JTAG_PLD_TDO_R")
	)
	(via
		(at 146.67992 -77.170788)
		(size 0.508)
		(drill 0.254)
		(layers "F.Cu" "B.Cu")
		(net "JTAG_PLD_TDO_R")
	)
	(via
		(at 172.955712 -110.175294)
		(size 0.4572)
		(drill 0.254)
		(layers "F.Cu" "B.Cu")
		(net "JTAG_PLD_TDO_R")
	)
	(via
		(at 162.74288 -109.565948)
		(size 0.508)
		(drill 0.254)
		(layers "F.Cu" "B.Cu")
		(net "JTAG_PLD_TDO_R")
	)
	(via
		(at 136.25068 -78.593188)
		(size 0.508)
		(drill 0.254)
		(layers "F.Cu" "B.Cu")
		(net "JTAG_PLD_TDO_R")
	)
	(segment
		(start 162.74288 -109.184948)
		(end 162.51428 -108.956348)
		(width 0.12954)
		(layer "B.Cu")
		(net "JTAG_PLD_TDO_R")
	)
	(segment
		(start 140.013436 -77.640688)
		(end 146.21002 -77.640688)
		(width 0.12954)
		(layer "B.Cu")
		(net "JTAG_PLD_TDO_R")
	)
	(segment
		(start 139.060936 -78.593188)
		(end 140.013436 -77.640688)
		(width 0.12954)
		(layer "B.Cu")
		(net "JTAG_PLD_TDO_R")
	)
	(segment
		(start 161.749994 -108.956348)
		(end 161.23793 -109.468412)
		(width 0.12954)
		(layer "B.Cu")
		(net "JTAG_PLD_TDO_R")
	)
	(segment
		(start 162.74288 -109.565948)
		(end 162.74288 -109.184948)
		(width 0.12954)
		(layer "B.Cu")
		(net "JTAG_PLD_TDO_R")
	)
	(segment
		(start 146.21002 -77.640688)
		(end 146.67992 -77.170788)
		(width 0.12954)
		(layer "B.Cu")
		(net "JTAG_PLD_TDO_R")
	)
	(segment
		(start 162.51428 -108.956348)
		(end 161.749994 -108.956348)
		(width 0.12954)
		(layer "B.Cu")
		(net "JTAG_PLD_TDO_R")
	)
	(segment
		(start 136.25068 -78.593188)
		(end 139.060936 -78.593188)
		(width 0.12954)
		(layer "B.Cu")
		(net "JTAG_PLD_TDO_R")
	)
	(segment
		(start 161.23793 -109.468412)
		(end 161.23793 -109.489748)
		(width 0.12954)
		(layer "B.Cu")
		(net "JTAG_PLD_TDO_R")
	)
	(segment
		(start 151.10968 -85.730588)
		(end 151.10968 -82.639408)
		(width 0.127)
		(layer "In2.Cu")
		(net "JTAG_PLD_TDO_R")
	)
	(segment
		(start 161.37763 -106.475784)
		(end 160.581594 -105.679748)
		(width 0.127)
		(layer "In2.Cu")
		(net "JTAG_PLD_TDO_R")
	)
	(segment
		(start 161.37763 -108.515658)
		(end 161.37763 -106.475784)
		(width 0.127)
		(layer "In2.Cu")
		(net "JTAG_PLD_TDO_R")
	)
	(segment
		(start 158.189676 -105.679748)
		(end 156.19476 -103.684832)
		(width 0.127)
		(layer "In2.Cu")
		(net "JTAG_PLD_TDO_R")
	)
	(segment
		(start 149.53488 -80.559148)
		(end 149.53488 -78.577948)
		(width 0.127)
		(layer "In2.Cu")
		(net "JTAG_PLD_TDO_R")
	)
	(segment
		(start 149.15388 -80.940148)
		(end 149.53488 -80.559148)
		(width 0.127)
		(layer "In2.Cu")
		(net "JTAG_PLD_TDO_R")
	)
	(segment
		(start 156.19476 -103.684832)
		(end 156.19476 -90.815668)
		(width 0.127)
		(layer "In2.Cu")
		(net "JTAG_PLD_TDO_R")
	)
	(segment
		(start 150.29688 -81.826608)
		(end 149.66188 -81.826608)
		(width 0.127)
		(layer "In2.Cu")
		(net "JTAG_PLD_TDO_R")
	)
	(segment
		(start 161.71418 -108.852208)
		(end 161.37763 -108.515658)
		(width 0.127)
		(layer "In2.Cu")
		(net "JTAG_PLD_TDO_R")
	)
	(segment
		(start 162.02914 -108.852208)
		(end 161.71418 -108.852208)
		(width 0.127)
		(layer "In2.Cu")
		(net "JTAG_PLD_TDO_R")
	)
	(segment
		(start 162.74288 -109.565948)
		(end 162.02914 -108.852208)
		(width 0.127)
		(layer "In2.Cu")
		(net "JTAG_PLD_TDO_R")
	)
	(segment
		(start 147.75688 -78.247748)
		(end 146.67992 -77.170788)
		(width 0.127)
		(layer "In2.Cu")
		(net "JTAG_PLD_TDO_R")
	)
	(segment
		(start 160.581594 -105.679748)
		(end 158.189676 -105.679748)
		(width 0.127)
		(layer "In2.Cu")
		(net "JTAG_PLD_TDO_R")
	)
	(segment
		(start 149.53488 -78.577948)
		(end 149.20468 -78.247748)
		(width 0.127)
		(layer "In2.Cu")
		(net "JTAG_PLD_TDO_R")
	)
	(segment
		(start 149.20468 -78.247748)
		(end 147.75688 -78.247748)
		(width 0.127)
		(layer "In2.Cu")
		(net "JTAG_PLD_TDO_R")
	)
	(segment
		(start 149.15388 -81.318608)
		(end 149.15388 -80.940148)
		(width 0.127)
		(layer "In2.Cu")
		(net "JTAG_PLD_TDO_R")
	)
	(segment
		(start 151.10968 -82.639408)
		(end 150.29688 -81.826608)
		(width 0.127)
		(layer "In2.Cu")
		(net "JTAG_PLD_TDO_R")
	)
	(segment
		(start 156.19476 -90.815668)
		(end 151.10968 -85.730588)
		(width 0.127)
		(layer "In2.Cu")
		(net "JTAG_PLD_TDO_R")
	)
	(segment
		(start 149.66188 -81.826608)
		(end 149.15388 -81.318608)
		(width 0.127)
		(layer "In2.Cu")
		(net "JTAG_PLD_TDO_R")
	)
	(segment
		(start 163.88588 -110.073948)
		(end 164.19068 -109.769148)
		(width 0.127)
		(layer "In6.Cu")
		(net "JTAG_PLD_TDO_R")
	)
	(segment
		(start 162.74288 -109.565948)
		(end 163.25088 -110.073948)
		(width 0.127)
		(layer "In6.Cu")
		(net "JTAG_PLD_TDO_R")
	)
	(segment
		(start 164.19068 -109.769148)
		(end 172.549566 -109.769148)
		(width 0.127)
		(layer "In6.Cu")
		(net "JTAG_PLD_TDO_R")
	)
	(segment
		(start 172.549566 -109.769148)
		(end 172.955712 -110.175294)
		(width 0.127)
		(layer "In6.Cu")
		(net "JTAG_PLD_TDO_R")
	)
	(segment
		(start 163.25088 -110.073948)
		(end 163.88588 -110.073948)
		(width 0.127)
		(layer "In6.Cu")
		(net "JTAG_PLD_TDO_R")
	)
	(segment
		(start 125.570488 -65.68186)
		(end 125.205744 -66.046604)
		(width 0.12954)
		(layer "F.Cu")
		(net "JTAG_PLD_TDI_R")
	)
	(segment
		(start 125.205744 -66.046604)
		(end 125.205744 -66.467228)
		(width 0.12954)
		(layer "F.Cu")
		(net "JTAG_PLD_TDI_R")
	)
	(segment
		(start 125.991112 -65.68186)
		(end 125.570488 -65.68186)
		(width 0.12954)
		(layer "F.Cu")
		(net "JTAG_PLD_TDI_R")
	)
	(segment
		(start 173.355762 -111.375444)
		(end 172.955712 -110.975394)
		(width 0.12954)
		(layer "F.Cu")
		(net "JTAG_PLD_TDI_R")
	)
	(via
		(at 125.991112 -65.68186)
		(size 0.508)
		(drill 0.254)
		(layers "F.Cu" "B.Cu")
		(net "JTAG_PLD_TDI_R")
	)
	(via
		(at 172.955712 -110.975394)
		(size 0.4572)
		(drill 0.254)
		(layers "F.Cu" "B.Cu")
		(net "JTAG_PLD_TDI_R")
	)
	(via
		(at 157.09138 -67.495928)
		(size 0.508)
		(drill 0.254)
		(layers "F.Cu" "B.Cu")
		(net "JTAG_PLD_TDI_R")
	)
	(segment
		(start 172.955712 -110.975394)
		(end 172.554138 -111.376968)
		(width 0.127)
		(layer "In2.Cu")
		(net "JTAG_PLD_TDI_R")
	)
	(segment
		(start 157.6705 -70.800468)
		(end 157.09138 -70.221348)
		(width 0.127)
		(layer "In2.Cu")
		(net "JTAG_PLD_TDI_R")
	)
	(segment
		(start 172.554138 -111.376968)
		(end 171.90974 -111.376968)
		(width 0.127)
		(layer "In2.Cu")
		(net "JTAG_PLD_TDI_R")
	)
	(segment
		(start 157.09138 -70.221348)
		(end 157.09138 -67.495928)
		(width 0.127)
		(layer "In2.Cu")
		(net "JTAG_PLD_TDI_R")
	)
	(segment
		(start 171.75988 -110.772448)
		(end 170.9547 -109.967268)
		(width 0.127)
		(layer "In2.Cu")
		(net "JTAG_PLD_TDI_R")
	)
	(segment
		(start 158.83636 -82.743294)
		(end 158.83636 -80.117188)
		(width 0.127)
		(layer "In2.Cu")
		(net "JTAG_PLD_TDI_R")
	)
	(segment
		(start 171.75988 -111.227108)
		(end 171.75988 -110.772448)
		(width 0.127)
		(layer "In2.Cu")
		(net "JTAG_PLD_TDI_R")
	)
	(segment
		(start 170.9547 -108.958888)
		(end 169.3545 -107.358688)
		(width 0.127)
		(layer "In2.Cu")
		(net "JTAG_PLD_TDI_R")
	)
	(segment
		(start 171.90974 -111.376968)
		(end 171.75988 -111.227108)
		(width 0.127)
		(layer "In2.Cu")
		(net "JTAG_PLD_TDI_R")
	)
	(segment
		(start 169.3545 -93.261434)
		(end 158.83636 -82.743294)
		(width 0.127)
		(layer "In2.Cu")
		(net "JTAG_PLD_TDI_R")
	)
	(segment
		(start 170.9547 -109.967268)
		(end 170.9547 -108.958888)
		(width 0.127)
		(layer "In2.Cu")
		(net "JTAG_PLD_TDI_R")
	)
	(segment
		(start 157.6705 -78.951328)
		(end 157.6705 -70.800468)
		(width 0.127)
		(layer "In2.Cu")
		(net "JTAG_PLD_TDI_R")
	)
	(segment
		(start 158.83636 -80.117188)
		(end 157.6705 -78.951328)
		(width 0.127)
		(layer "In2.Cu")
		(net "JTAG_PLD_TDI_R")
	)
	(segment
		(start 169.3545 -107.358688)
		(end 169.3545 -93.261434)
		(width 0.127)
		(layer "In2.Cu")
		(net "JTAG_PLD_TDI_R")
	)
	(segment
		(start 147.56511 -63.150242)
		(end 149.988016 -65.573148)
		(width 0.127)
		(layer "In6.Cu")
		(net "JTAG_PLD_TDI_R")
	)
	(segment
		(start 153.422096 -66.685668)
		(end 156.28112 -66.685668)
		(width 0.127)
		(layer "In6.Cu")
		(net "JTAG_PLD_TDI_R")
	)
	(segment
		(start 138.8237 -64.186308)
		(end 139.859766 -63.150242)
		(width 0.127)
		(layer "In6.Cu")
		(net "JTAG_PLD_TDI_R")
	)
	(segment
		(start 125.991112 -65.68186)
		(end 133.038088 -65.68186)
		(width 0.127)
		(layer "In6.Cu")
		(net "JTAG_PLD_TDI_R")
	)
	(segment
		(start 133.038088 -65.68186)
		(end 134.53364 -64.186308)
		(width 0.127)
		(layer "In6.Cu")
		(net "JTAG_PLD_TDI_R")
	)
	(segment
		(start 156.28112 -66.685668)
		(end 157.09138 -67.495928)
		(width 0.127)
		(layer "In6.Cu")
		(net "JTAG_PLD_TDI_R")
	)
	(segment
		(start 134.53364 -64.186308)
		(end 138.8237 -64.186308)
		(width 0.127)
		(layer "In6.Cu")
		(net "JTAG_PLD_TDI_R")
	)
	(segment
		(start 152.309576 -65.573148)
		(end 153.422096 -66.685668)
		(width 0.127)
		(layer "In6.Cu")
		(net "JTAG_PLD_TDI_R")
	)
	(segment
		(start 149.988016 -65.573148)
		(end 152.309576 -65.573148)
		(width 0.127)
		(layer "In6.Cu")
		(net "JTAG_PLD_TDI_R")
	)
	(segment
		(start 139.859766 -63.150242)
		(end 147.56511 -63.150242)
		(width 0.127)
		(layer "In6.Cu")
		(net "JTAG_PLD_TDI_R")
	)
	(segment
		(start 114.826034 -66.272156)
		(end 114.826034 -64.734948)
		(width 0.12954)
		(layer "F.Cu")
		(net "JTAG_PLD_TCK_R")
	)
	(segment
		(start 172.555662 -112.175544)
		(end 172.155612 -111.775494)
		(width 0.12954)
		(layer "F.Cu")
		(net "JTAG_PLD_TCK_R")
	)
	(via
		(at 158.04388 -115.026948)
		(size 0.508)
		(drill 0.254)
		(layers "F.Cu" "B.Cu")
		(net "JTAG_PLD_TCK_R")
	)
	(via
		(at 172.155612 -111.775494)
		(size 0.4572)
		(drill 0.254)
		(layers "F.Cu" "B.Cu")
		(net "JTAG_PLD_TCK_R")
	)
	(via
		(at 114.826034 -64.734948)
		(size 0.508)
		(drill 0.254)
		(layers "F.Cu" "B.Cu")
		(net "JTAG_PLD_TCK_R")
	)
	(segment
		(start 150.10384 -97.143824)
		(end 145.84934 -92.889324)
		(width 0.127)
		(layer "In2.Cu")
		(net "JTAG_PLD_TCK_R")
	)
	(segment
		(start 150.797006 -109.735874)
		(end 150.797006 -107.642406)
		(width 0.127)
		(layer "In2.Cu")
		(net "JTAG_PLD_TCK_R")
	)
	(segment
		(start 115.26647 -74.494898)
		(end 115.7859 -73.975468)
		(width 0.127)
		(layer "In2.Cu")
		(net "JTAG_PLD_TCK_R")
	)
	(segment
		(start 120.062498 -83.111594)
		(end 115.26647 -78.315566)
		(width 0.127)
		(layer "In2.Cu")
		(net "JTAG_PLD_TCK_R")
	)
	(segment
		(start 115.26647 -78.315566)
		(end 115.26647 -74.494898)
		(width 0.127)
		(layer "In2.Cu")
		(net "JTAG_PLD_TCK_R")
	)
	(segment
		(start 150.10384 -106.94924)
		(end 150.10384 -97.143824)
		(width 0.127)
		(layer "In2.Cu")
		(net "JTAG_PLD_TCK_R")
	)
	(segment
		(start 115.7859 -73.975468)
		(end 115.7859 -69.111368)
		(width 0.127)
		(layer "In2.Cu")
		(net "JTAG_PLD_TCK_R")
	)
	(segment
		(start 156.81706 -114.407188)
		(end 155.46832 -114.407188)
		(width 0.127)
		(layer "In2.Cu")
		(net "JTAG_PLD_TCK_R")
	)
	(segment
		(start 150.797006 -107.642406)
		(end 150.10384 -106.94924)
		(width 0.127)
		(layer "In2.Cu")
		(net "JTAG_PLD_TCK_R")
	)
	(segment
		(start 157.43682 -115.026948)
		(end 156.81706 -114.407188)
		(width 0.127)
		(layer "In2.Cu")
		(net "JTAG_PLD_TCK_R")
	)
	(segment
		(start 145.84934 -92.889324)
		(end 145.84934 -84.3026)
		(width 0.127)
		(layer "In2.Cu")
		(net "JTAG_PLD_TCK_R")
	)
	(segment
		(start 114.826034 -68.151502)
		(end 114.826034 -64.734948)
		(width 0.127)
		(layer "In2.Cu")
		(net "JTAG_PLD_TCK_R")
	)
	(segment
		(start 115.7859 -69.111368)
		(end 114.826034 -68.151502)
		(width 0.127)
		(layer "In2.Cu")
		(net "JTAG_PLD_TCK_R")
	)
	(segment
		(start 144.658334 -83.111594)
		(end 120.062498 -83.111594)
		(width 0.127)
		(layer "In2.Cu")
		(net "JTAG_PLD_TCK_R")
	)
	(segment
		(start 145.84934 -84.3026)
		(end 144.658334 -83.111594)
		(width 0.127)
		(layer "In2.Cu")
		(net "JTAG_PLD_TCK_R")
	)
	(segment
		(start 155.46832 -114.407188)
		(end 150.797006 -109.735874)
		(width 0.127)
		(layer "In2.Cu")
		(net "JTAG_PLD_TCK_R")
	)
	(segment
		(start 158.04388 -115.026948)
		(end 157.43682 -115.026948)
		(width 0.127)
		(layer "In2.Cu")
		(net "JTAG_PLD_TCK_R")
	)
	(segment
		(start 169.293032 -113.256568)
		(end 170.375072 -112.174528)
		(width 0.127)
		(layer "In6.Cu")
		(net "JTAG_PLD_TCK_R")
	)
	(segment
		(start 162.257232 -113.256568)
		(end 169.293032 -113.256568)
		(width 0.127)
		(layer "In6.Cu")
		(net "JTAG_PLD_TCK_R")
	)
	(segment
		(start 160.016952 -115.496848)
		(end 162.257232 -113.256568)
		(width 0.127)
		(layer "In6.Cu")
		(net "JTAG_PLD_TCK_R")
	)
	(segment
		(start 158.51378 -115.496848)
		(end 160.016952 -115.496848)
		(width 0.127)
		(layer "In6.Cu")
		(net "JTAG_PLD_TCK_R")
	)
	(segment
		(start 158.04388 -115.026948)
		(end 158.51378 -115.496848)
		(width 0.127)
		(layer "In6.Cu")
		(net "JTAG_PLD_TCK_R")
	)
	(segment
		(start 170.375072 -112.174528)
		(end 171.756578 -112.174528)
		(width 0.127)
		(layer "In6.Cu")
		(net "JTAG_PLD_TCK_R")
	)
	(segment
		(start 171.756578 -112.174528)
		(end 172.155612 -111.775494)
		(width 0.127)
		(layer "In6.Cu")
		(net "JTAG_PLD_TCK_R")
	)
	(segment
		(start 173.355762 -115.375436)
		(end 172.955712 -115.775486)
		(width 0.12954)
		(layer "F.Cu")
		(net "JTAG_PLD_JTAGEN")
	)
	(via
		(at 172.955712 -115.775486)
		(size 0.4572)
		(drill 0.254)
		(layers "F.Cu" "B.Cu")
		(net "JTAG_PLD_JTAGEN")
	)
	(via
		(at 123.6472 -65.827148)
		(size 0.508)
		(drill 0.254)
		(layers "F.Cu" "B.Cu")
		(net "JTAG_PLD_JTAGEN")
	)
	(via
		(at 156.0068 -67.511168)
		(size 0.508)
		(drill 0.254)
		(layers "F.Cu" "B.Cu")
		(net "JTAG_PLD_JTAGEN")
	)
	(segment
		(start 161.574226 -116.906548)
		(end 164.38753 -116.906548)
		(width 0.12954)
		(layer "B.Cu")
		(net "JTAG_PLD_JTAGEN")
	)
	(segment
		(start 165.04793 -117.268244)
		(end 165.04793 -117.566948)
		(width 0.12954)
		(layer "B.Cu")
		(net "JTAG_PLD_JTAGEN")
	)
	(segment
		(start 164.38753 -116.906548)
		(end 165.04793 -117.566948)
		(width 0.12954)
		(layer "B.Cu")
		(net "JTAG_PLD_JTAGEN")
	)
	(segment
		(start 165.282626 -117.033548)
		(end 165.04793 -117.268244)
		(width 0.12954)
		(layer "B.Cu")
		(net "JTAG_PLD_JTAGEN")
	)
	(segment
		(start 165.7604 -117.033548)
		(end 165.282626 -117.033548)
		(width 0.12954)
		(layer "B.Cu")
		(net "JTAG_PLD_JTAGEN")
	)
	(segment
		(start 172.55871 -116.172488)
		(end 166.62146 -116.172488)
		(width 0.12954)
		(layer "B.Cu")
		(net "JTAG_PLD_JTAGEN")
	)
	(segment
		(start 161.23793 -117.242844)
		(end 161.574226 -116.906548)
		(width 0.12954)
		(layer "B.Cu")
		(net "JTAG_PLD_JTAGEN")
	)
	(segment
		(start 161.23793 -117.566948)
		(end 161.23793 -117.242844)
		(width 0.12954)
		(layer "B.Cu")
		(net "JTAG_PLD_JTAGEN")
	)
	(segment
		(start 172.955712 -115.775486)
		(end 172.55871 -116.172488)
		(width 0.12954)
		(layer "B.Cu")
		(net "JTAG_PLD_JTAGEN")
	)
	(segment
		(start 166.62146 -116.172488)
		(end 165.7604 -117.033548)
		(width 0.12954)
		(layer "B.Cu")
		(net "JTAG_PLD_JTAGEN")
	)
	(segment
		(start 167.83558 -111.239808)
		(end 170.1038 -113.508028)
		(width 0.127)
		(layer "In2.Cu")
		(net "JTAG_PLD_JTAGEN")
	)
	(segment
		(start 172.5549 -115.374674)
		(end 172.955712 -115.775486)
		(width 0.127)
		(layer "In2.Cu")
		(net "JTAG_PLD_JTAGEN")
	)
	(segment
		(start 172.5549 -113.769648)
		(end 172.5549 -115.374674)
		(width 0.127)
		(layer "In2.Cu")
		(net "JTAG_PLD_JTAGEN")
	)
	(segment
		(start 170.1038 -113.508028)
		(end 172.29328 -113.508028)
		(width 0.127)
		(layer "In2.Cu")
		(net "JTAG_PLD_JTAGEN")
	)
	(segment
		(start 162.0266 -95.976948)
		(end 163.3474 -97.297748)
		(width 0.127)
		(layer "In2.Cu")
		(net "JTAG_PLD_JTAGEN")
	)
	(segment
		(start 156.0068 -67.511168)
		(end 156.0068 -78.725268)
		(width 0.127)
		(layer "In2.Cu")
		(net "JTAG_PLD_JTAGEN")
	)
	(segment
		(start 167.34536 -103.251508)
		(end 167.34536 -103.913432)
		(width 0.127)
		(layer "In2.Cu")
		(net "JTAG_PLD_JTAGEN")
	)
	(segment
		(start 157.29712 -80.015588)
		(end 157.29712 -82.555588)
		(width 0.127)
		(layer "In2.Cu")
		(net "JTAG_PLD_JTAGEN")
	)
	(segment
		(start 162.0266 -87.285068)
		(end 162.0266 -95.976948)
		(width 0.127)
		(layer "In2.Cu")
		(net "JTAG_PLD_JTAGEN")
	)
	(segment
		(start 156.0068 -78.725268)
		(end 157.29712 -80.015588)
		(width 0.127)
		(layer "In2.Cu")
		(net "JTAG_PLD_JTAGEN")
	)
	(segment
		(start 163.3474 -97.297748)
		(end 163.3474 -99.7585)
		(width 0.127)
		(layer "In2.Cu")
		(net "JTAG_PLD_JTAGEN")
	)
	(segment
		(start 157.29712 -82.555588)
		(end 162.0266 -87.285068)
		(width 0.127)
		(layer "In2.Cu")
		(net "JTAG_PLD_JTAGEN")
	)
	(segment
		(start 164.8079 -100.714048)
		(end 167.34536 -103.251508)
		(width 0.127)
		(layer "In2.Cu")
		(net "JTAG_PLD_JTAGEN")
	)
	(segment
		(start 167.34536 -103.913432)
		(end 167.83558 -104.403652)
		(width 0.127)
		(layer "In2.Cu")
		(net "JTAG_PLD_JTAGEN")
	)
	(segment
		(start 172.29328 -113.508028)
		(end 172.5549 -113.769648)
		(width 0.127)
		(layer "In2.Cu")
		(net "JTAG_PLD_JTAGEN")
	)
	(segment
		(start 163.3474 -99.7585)
		(end 164.302948 -100.714048)
		(width 0.127)
		(layer "In2.Cu")
		(net "JTAG_PLD_JTAGEN")
	)
	(segment
		(start 164.302948 -100.714048)
		(end 164.8079 -100.714048)
		(width 0.127)
		(layer "In2.Cu")
		(net "JTAG_PLD_JTAGEN")
	)
	(segment
		(start 167.83558 -104.403652)
		(end 167.83558 -111.239808)
		(width 0.127)
		(layer "In2.Cu")
		(net "JTAG_PLD_JTAGEN")
	)
	(segment
		(start 138.94308 -64.701928)
		(end 140.062966 -63.582042)
		(width 0.127)
		(layer "In6.Cu")
		(net "JTAG_PLD_JTAGEN")
	)
	(segment
		(start 133.223 -66.182748)
		(end 134.70382 -64.701928)
		(width 0.127)
		(layer "In6.Cu")
		(net "JTAG_PLD_JTAGEN")
	)
	(segment
		(start 140.062966 -63.582042)
		(end 147.385786 -63.582042)
		(width 0.127)
		(layer "In6.Cu")
		(net "JTAG_PLD_JTAGEN")
	)
	(segment
		(start 155.6385 -67.142868)
		(end 156.0068 -67.511168)
		(width 0.127)
		(layer "In6.Cu")
		(net "JTAG_PLD_JTAGEN")
	)
	(segment
		(start 123.6472 -65.827148)
		(end 124.0028 -66.182748)
		(width 0.127)
		(layer "In6.Cu")
		(net "JTAG_PLD_JTAGEN")
	)
	(segment
		(start 152.130252 -66.004948)
		(end 153.268172 -67.142868)
		(width 0.127)
		(layer "In6.Cu")
		(net "JTAG_PLD_JTAGEN")
	)
	(segment
		(start 134.70382 -64.701928)
		(end 138.94308 -64.701928)
		(width 0.127)
		(layer "In6.Cu")
		(net "JTAG_PLD_JTAGEN")
	)
	(segment
		(start 149.808692 -66.004948)
		(end 152.130252 -66.004948)
		(width 0.127)
		(layer "In6.Cu")
		(net "JTAG_PLD_JTAGEN")
	)
	(segment
		(start 147.385786 -63.582042)
		(end 149.808692 -66.004948)
		(width 0.127)
		(layer "In6.Cu")
		(net "JTAG_PLD_JTAGEN")
	)
	(segment
		(start 153.268172 -67.142868)
		(end 155.6385 -67.142868)
		(width 0.127)
		(layer "In6.Cu")
		(net "JTAG_PLD_JTAGEN")
	)
	(segment
		(start 124.0028 -66.182748)
		(end 133.223 -66.182748)
		(width 0.127)
		(layer "In6.Cu")
		(net "JTAG_PLD_JTAGEN")
	)
	(segment
		(start 370.683282 -58.533792)
		(end 371.813582 -58.533792)
		(width 0.12954)
		(layer "F.Cu")
		(net "JTAG_MUX_QS_GTL_TDO")
	)
	(segment
		(start 295.60139 -142.142718)
		(end 295.63568 -142.142718)
		(width 0.12954)
		(layer "F.Cu")
		(net "JTAG_MUX_QS_GTL_TDO")
	)
	(segment
		(start 250.64466 -151.295608)
		(end 255.62814 -146.312128)
		(width 0.12954)
		(layer "F.Cu")
		(net "JTAG_MUX_QS_GTL_TDO")
	)
	(segment
		(start 352.039682 -127.982726)
		(end 352.28022 -127.742188)
		(width 0.12954)
		(layer "F.Cu")
		(net "JTAG_MUX_QS_GTL_TDO")
	)
	(segment
		(start 352.28022 -127.742188)
		(end 352.4377 -127.742188)
		(width 0.12954)
		(layer "F.Cu")
		(net "JTAG_MUX_QS_GTL_TDO")
	)
	(segment
		(start 218.411552 -150.86838)
		(end 218.83878 -151.295608)
		(width 0.12954)
		(layer "F.Cu")
		(net "JTAG_MUX_QS_GTL_TDO")
	)
	(segment
		(start 255.62814 -146.312128)
		(end 291.43198 -146.312128)
		(width 0.12954)
		(layer "F.Cu")
		(net "JTAG_MUX_QS_GTL_TDO")
	)
	(segment
		(start 291.43198 -146.312128)
		(end 295.60139 -142.142718)
		(width 0.12954)
		(layer "F.Cu")
		(net "JTAG_MUX_QS_GTL_TDO")
	)
	(segment
		(start 218.83878 -151.295608)
		(end 250.64466 -151.295608)
		(width 0.12954)
		(layer "F.Cu")
		(net "JTAG_MUX_QS_GTL_TDO")
	)
	(segment
		(start 309.795672 -127.982726)
		(end 352.039682 -127.982726)
		(width 0.12954)
		(layer "F.Cu")
		(net "JTAG_MUX_QS_GTL_TDO")
	)
	(segment
		(start 295.63568 -142.142718)
		(end 309.795672 -127.982726)
		(width 0.12954)
		(layer "F.Cu")
		(net "JTAG_MUX_QS_GTL_TDO")
	)
	(via
		(at 218.411552 -150.86838)
		(size 0.508)
		(drill 0.254)
		(layers "F.Cu" "B.Cu")
		(net "JTAG_MUX_QS_GTL_TDO")
	)
	(via
		(at 214.619078 -193.81851)
		(size 0.508)
		(drill 0.254)
		(layers "F.Cu" "B.Cu")
		(net "JTAG_MUX_QS_GTL_TDO")
	)
	(via
		(at 371.813582 -58.533792)
		(size 0.508)
		(drill 0.254)
		(layers "F.Cu" "B.Cu")
		(net "JTAG_MUX_QS_GTL_TDO")
	)
	(via
		(at 352.4377 -127.742188)
		(size 0.508)
		(drill 0.254)
		(layers "F.Cu" "B.Cu")
		(net "JTAG_MUX_QS_GTL_TDO")
	)
	(segment
		(start 211.61248 -192.276984)
		(end 211.61248 -192.779904)
		(width 0.12954)
		(layer "B.Cu")
		(net "JTAG_MUX_QS_GTL_TDO")
	)
	(segment
		(start 214.309198 -192.14719)
		(end 211.742274 -192.14719)
		(width 0.12954)
		(layer "B.Cu")
		(net "JTAG_MUX_QS_GTL_TDO")
	)
	(segment
		(start 214.619078 -192.45707)
		(end 214.309198 -192.14719)
		(width 0.12954)
		(layer "B.Cu")
		(net "JTAG_MUX_QS_GTL_TDO")
	)
	(segment
		(start 214.619078 -193.81851)
		(end 214.619078 -192.45707)
		(width 0.12954)
		(layer "B.Cu")
		(net "JTAG_MUX_QS_GTL_TDO")
	)
	(segment
		(start 211.742274 -192.14719)
		(end 211.61248 -192.276984)
		(width 0.12954)
		(layer "B.Cu")
		(net "JTAG_MUX_QS_GTL_TDO")
	)
	(segment
		(start 215.678258 -161.65703)
		(end 215.678258 -192.75933)
		(width 0.127)
		(layer "In2.Cu")
		(net "JTAG_MUX_QS_GTL_TDO")
	)
	(segment
		(start 370.41328 -71.719948)
		(end 368.6937 -73.439528)
		(width 0.127)
		(layer "In2.Cu")
		(net "JTAG_MUX_QS_GTL_TDO")
	)
	(segment
		(start 355.972618 -126.32563)
		(end 354.55606 -127.742188)
		(width 0.127)
		(layer "In2.Cu")
		(net "JTAG_MUX_QS_GTL_TDO")
	)
	(segment
		(start 366.50676 -102.570788)
		(end 366.50676 -109.160818)
		(width 0.127)
		(layer "In2.Cu")
		(net "JTAG_MUX_QS_GTL_TDO")
	)
	(segment
		(start 368.6937 -86.484968)
		(end 370.0907 -87.881968)
		(width 0.127)
		(layer "In2.Cu")
		(net "JTAG_MUX_QS_GTL_TDO")
	)
	(segment
		(start 216.933018 -153.431494)
		(end 216.933018 -160.40227)
		(width 0.127)
		(layer "In2.Cu")
		(net "JTAG_MUX_QS_GTL_TDO")
	)
	(segment
		(start 373.5578 -94.478348)
		(end 373.0752 -94.960948)
		(width 0.127)
		(layer "In2.Cu")
		(net "JTAG_MUX_QS_GTL_TDO")
	)
	(segment
		(start 370.41328 -59.502548)
		(end 370.41328 -71.719948)
		(width 0.127)
		(layer "In2.Cu")
		(net "JTAG_MUX_QS_GTL_TDO")
	)
	(segment
		(start 373.0752 -96.002348)
		(end 366.50676 -102.570788)
		(width 0.127)
		(layer "In2.Cu")
		(net "JTAG_MUX_QS_GTL_TDO")
	)
	(segment
		(start 215.678258 -192.75933)
		(end 214.619078 -193.81851)
		(width 0.127)
		(layer "In2.Cu")
		(net "JTAG_MUX_QS_GTL_TDO")
	)
	(segment
		(start 370.75618 -87.881968)
		(end 373.5578 -90.683588)
		(width 0.127)
		(layer "In2.Cu")
		(net "JTAG_MUX_QS_GTL_TDO")
	)
	(segment
		(start 216.933018 -160.40227)
		(end 215.678258 -161.65703)
		(width 0.127)
		(layer "In2.Cu")
		(net "JTAG_MUX_QS_GTL_TDO")
	)
	(segment
		(start 354.55606 -127.742188)
		(end 352.4377 -127.742188)
		(width 0.127)
		(layer "In2.Cu")
		(net "JTAG_MUX_QS_GTL_TDO")
	)
	(segment
		(start 368.6937 -73.439528)
		(end 368.6937 -86.484968)
		(width 0.127)
		(layer "In2.Cu")
		(net "JTAG_MUX_QS_GTL_TDO")
	)
	(segment
		(start 370.0907 -87.881968)
		(end 370.75618 -87.881968)
		(width 0.127)
		(layer "In2.Cu")
		(net "JTAG_MUX_QS_GTL_TDO")
	)
	(segment
		(start 218.411552 -150.86838)
		(end 218.411552 -151.95296)
		(width 0.127)
		(layer "In2.Cu")
		(net "JTAG_MUX_QS_GTL_TDO")
	)
	(segment
		(start 373.0752 -94.960948)
		(end 373.0752 -96.002348)
		(width 0.127)
		(layer "In2.Cu")
		(net "JTAG_MUX_QS_GTL_TDO")
	)
	(segment
		(start 218.411552 -151.95296)
		(end 216.933018 -153.431494)
		(width 0.127)
		(layer "In2.Cu")
		(net "JTAG_MUX_QS_GTL_TDO")
	)
	(segment
		(start 371.813582 -58.533792)
		(end 371.382036 -58.533792)
		(width 0.127)
		(layer "In2.Cu")
		(net "JTAG_MUX_QS_GTL_TDO")
	)
	(segment
		(start 373.5578 -90.683588)
		(end 373.5578 -94.478348)
		(width 0.127)
		(layer "In2.Cu")
		(net "JTAG_MUX_QS_GTL_TDO")
	)
	(segment
		(start 371.382036 -58.533792)
		(end 370.41328 -59.502548)
		(width 0.127)
		(layer "In2.Cu")
		(net "JTAG_MUX_QS_GTL_TDO")
	)
	(segment
		(start 366.50676 -109.160818)
		(end 355.972618 -126.32563)
		(width 0.127)
		(layer "In2.Cu")
		(net "JTAG_MUX_QS_GTL_TDO")
	)
	(via
		(at 96.77654 -186.621928)
		(size 0.508)
		(drill 0.254)
		(layers "F.Cu" "B.Cu")
		(net "JTAG_MUX_CPU1_GTL_TDI")
	)
	(via
		(at 206.95158 -194.023996)
		(size 0.508)
		(drill 0.254)
		(layers "F.Cu" "B.Cu")
		(net "JTAG_MUX_CPU1_GTL_TDI")
	)
	(segment
		(start 97.257108 -190.305182)
		(end 97.651316 -190.69939)
		(width 0.12954)
		(layer "B.Cu")
		(net "JTAG_MUX_CPU1_GTL_TDI")
	)
	(segment
		(start 218.495118 -197.20433)
		(end 213.783418 -197.20433)
		(width 0.12954)
		(layer "B.Cu")
		(net "JTAG_MUX_CPU1_GTL_TDI")
	)
	(segment
		(start 207.955896 -195.204588)
		(end 207.955896 -194.023996)
		(width 0.12954)
		(layer "B.Cu")
		(net "JTAG_MUX_CPU1_GTL_TDI")
	)
	(segment
		(start 208.525618 -195.77431)
		(end 207.955896 -195.204588)
		(width 0.12954)
		(layer "B.Cu")
		(net "JTAG_MUX_CPU1_GTL_TDI")
	)
	(segment
		(start 96.77654 -186.621928)
		(end 97.436432 -187.28182)
		(width 0.12954)
		(layer "B.Cu")
		(net "JTAG_MUX_CPU1_GTL_TDI")
	)
	(segment
		(start 208.525618 -196.84111)
		(end 208.525618 -195.77431)
		(width 0.12954)
		(layer "B.Cu")
		(net "JTAG_MUX_CPU1_GTL_TDI")
	)
	(segment
		(start 207.955896 -194.023996)
		(end 206.95158 -194.023996)
		(width 0.12954)
		(layer "B.Cu")
		(net "JTAG_MUX_CPU1_GTL_TDI")
	)
	(segment
		(start 99.079558 -190.719456)
		(end 98.693732 -191.105282)
		(width 0.12954)
		(layer "B.Cu")
		(net "JTAG_MUX_CPU1_GTL_TDI")
	)
	(segment
		(start 213.783418 -197.20433)
		(end 213.321138 -196.74205)
		(width 0.12954)
		(layer "B.Cu")
		(net "JTAG_MUX_CPU1_GTL_TDI")
	)
	(segment
		(start 97.993708 -187.28182)
		(end 99.079558 -188.36767)
		(width 0.12954)
		(layer "B.Cu")
		(net "JTAG_MUX_CPU1_GTL_TDI")
	)
	(segment
		(start 213.321138 -196.74205)
		(end 210.318858 -196.74205)
		(width 0.12954)
		(layer "B.Cu")
		(net "JTAG_MUX_CPU1_GTL_TDI")
	)
	(segment
		(start 97.436432 -187.28182)
		(end 97.993708 -187.28182)
		(width 0.12954)
		(layer "B.Cu")
		(net "JTAG_MUX_CPU1_GTL_TDI")
	)
	(segment
		(start 219.358718 -196.34073)
		(end 218.495118 -197.20433)
		(width 0.12954)
		(layer "B.Cu")
		(net "JTAG_MUX_CPU1_GTL_TDI")
	)
	(segment
		(start 219.023184 -194.41795)
		(end 219.358718 -194.753484)
		(width 0.12954)
		(layer "B.Cu")
		(net "JTAG_MUX_CPU1_GTL_TDI")
	)
	(segment
		(start 219.358718 -194.753484)
		(end 219.358718 -196.34073)
		(width 0.12954)
		(layer "B.Cu")
		(net "JTAG_MUX_CPU1_GTL_TDI")
	)
	(segment
		(start 97.867216 -190.69939)
		(end 98.273108 -191.105282)
		(width 0.12954)
		(layer "B.Cu")
		(net "JTAG_MUX_CPU1_GTL_TDI")
	)
	(segment
		(start 209.843878 -197.21703)
		(end 208.901538 -197.21703)
		(width 0.12954)
		(layer "B.Cu")
		(net "JTAG_MUX_CPU1_GTL_TDI")
	)
	(segment
		(start 218.2114 -194.41795)
		(end 219.023184 -194.41795)
		(width 0.12954)
		(layer "B.Cu")
		(net "JTAG_MUX_CPU1_GTL_TDI")
	)
	(segment
		(start 98.693732 -191.105282)
		(end 98.273108 -191.105282)
		(width 0.12954)
		(layer "B.Cu")
		(net "JTAG_MUX_CPU1_GTL_TDI")
	)
	(segment
		(start 208.901538 -197.21703)
		(end 208.525618 -196.84111)
		(width 0.12954)
		(layer "B.Cu")
		(net "JTAG_MUX_CPU1_GTL_TDI")
	)
	(segment
		(start 210.318858 -196.74205)
		(end 209.843878 -197.21703)
		(width 0.12954)
		(layer "B.Cu")
		(net "JTAG_MUX_CPU1_GTL_TDI")
	)
	(segment
		(start 99.079558 -188.36767)
		(end 99.079558 -190.719456)
		(width 0.12954)
		(layer "B.Cu")
		(net "JTAG_MUX_CPU1_GTL_TDI")
	)
	(segment
		(start 97.651316 -190.69939)
		(end 97.867216 -190.69939)
		(width 0.12954)
		(layer "B.Cu")
		(net "JTAG_MUX_CPU1_GTL_TDI")
	)
	(segment
		(start 97.83572 -185.562748)
		(end 162.48888 -185.562748)
		(width 0.127)
		(layer "In13.Cu")
		(net "JTAG_MUX_CPU1_GTL_TDI")
	)
	(segment
		(start 205.486254 -191.222122)
		(end 206.25308 -191.988948)
		(width 0.127)
		(layer "In13.Cu")
		(net "JTAG_MUX_CPU1_GTL_TDI")
	)
	(segment
		(start 202.72248 -189.118748)
		(end 204.825854 -191.222122)
		(width 0.127)
		(layer "In13.Cu")
		(net "JTAG_MUX_CPU1_GTL_TDI")
	)
	(segment
		(start 162.48888 -185.562748)
		(end 167.56888 -190.642748)
		(width 0.127)
		(layer "In13.Cu")
		(net "JTAG_MUX_CPU1_GTL_TDI")
	)
	(segment
		(start 201.19848 -189.118748)
		(end 202.72248 -189.118748)
		(width 0.127)
		(layer "In13.Cu")
		(net "JTAG_MUX_CPU1_GTL_TDI")
	)
	(segment
		(start 170.94708 -190.642748)
		(end 173.91888 -187.670948)
		(width 0.127)
		(layer "In13.Cu")
		(net "JTAG_MUX_CPU1_GTL_TDI")
	)
	(segment
		(start 199.175878 -187.670948)
		(end 200.15708 -188.077348)
		(width 0.127)
		(layer "In13.Cu")
		(net "JTAG_MUX_CPU1_GTL_TDI")
	)
	(segment
		(start 206.25308 -191.988948)
		(end 206.25308 -193.325496)
		(width 0.127)
		(layer "In13.Cu")
		(net "JTAG_MUX_CPU1_GTL_TDI")
	)
	(segment
		(start 167.56888 -190.642748)
		(end 170.94708 -190.642748)
		(width 0.127)
		(layer "In13.Cu")
		(net "JTAG_MUX_CPU1_GTL_TDI")
	)
	(segment
		(start 206.25308 -193.325496)
		(end 206.95158 -194.023996)
		(width 0.127)
		(layer "In13.Cu")
		(net "JTAG_MUX_CPU1_GTL_TDI")
	)
	(segment
		(start 200.15708 -188.077348)
		(end 201.19848 -189.118748)
		(width 0.127)
		(layer "In13.Cu")
		(net "JTAG_MUX_CPU1_GTL_TDI")
	)
	(segment
		(start 173.91888 -187.670948)
		(end 199.175878 -187.670948)
		(width 0.127)
		(layer "In13.Cu")
		(net "JTAG_MUX_CPU1_GTL_TDI")
	)
	(segment
		(start 204.825854 -191.222122)
		(end 205.486254 -191.222122)
		(width 0.127)
		(layer "In13.Cu")
		(net "JTAG_MUX_CPU1_GTL_TDI")
	)
	(segment
		(start 96.77654 -186.621928)
		(end 97.83572 -185.562748)
		(width 0.127)
		(layer "In13.Cu")
		(net "JTAG_MUX_CPU1_GTL_TDI")
	)
	(segment
		(start 225.918776 -188.222636)
		(end 225.698304 -188.443108)
		(width 0.12954)
		(layer "F.Cu")
		(net "JTAG_MUX_CPU0_GTL_TDI")
	)
	(segment
		(start 290.78174 -155.895548)
		(end 286.08274 -160.594548)
		(width 0.12954)
		(layer "F.Cu")
		(net "JTAG_MUX_CPU0_GTL_TDI")
	)
	(segment
		(start 246.21998 -171.008548)
		(end 229.005892 -188.222636)
		(width 0.12954)
		(layer "F.Cu")
		(net "JTAG_MUX_CPU0_GTL_TDI")
	)
	(segment
		(start 286.08274 -160.937448)
		(end 276.01164 -171.008548)
		(width 0.12954)
		(layer "F.Cu")
		(net "JTAG_MUX_CPU0_GTL_TDI")
	)
	(segment
		(start 225.698304 -188.443108)
		(end 225.22688 -188.443108)
		(width 0.12954)
		(layer "F.Cu")
		(net "JTAG_MUX_CPU0_GTL_TDI")
	)
	(segment
		(start 286.08274 -160.594548)
		(end 286.08274 -160.937448)
		(width 0.12954)
		(layer "F.Cu")
		(net "JTAG_MUX_CPU0_GTL_TDI")
	)
	(segment
		(start 276.01164 -171.008548)
		(end 246.21998 -171.008548)
		(width 0.12954)
		(layer "F.Cu")
		(net "JTAG_MUX_CPU0_GTL_TDI")
	)
	(segment
		(start 229.005892 -188.222636)
		(end 225.918776 -188.222636)
		(width 0.12954)
		(layer "F.Cu")
		(net "JTAG_MUX_CPU0_GTL_TDI")
	)
	(via
		(at 208.882996 -192.287906)
		(size 0.508)
		(drill 0.254)
		(layers "F.Cu" "B.Cu")
		(net "JTAG_MUX_CPU0_GTL_TDI")
	)
	(via
		(at 290.78174 -155.895548)
		(size 0.508)
		(drill 0.254)
		(layers "F.Cu" "B.Cu")
		(net "JTAG_MUX_CPU0_GTL_TDI")
	)
	(via
		(at 225.22688 -188.443108)
		(size 0.508)
		(drill 0.254)
		(layers "F.Cu" "B.Cu")
		(net "JTAG_MUX_CPU0_GTL_TDI")
	)
	(segment
		(start 291.24402 -156.357828)
		(end 309.22976 -156.357828)
		(width 0.12954)
		(layer "B.Cu")
		(net "JTAG_MUX_CPU0_GTL_TDI")
	)
	(segment
		(start 337.905852 -187.598558)
		(end 337.903312 -187.596018)
		(width 0.12954)
		(layer "B.Cu")
		(net "JTAG_MUX_CPU0_GTL_TDI")
	)
	(segment
		(start 320.60388 -167.731948)
		(end 326.85228 -167.731948)
		(width 0.12954)
		(layer "B.Cu")
		(net "JTAG_MUX_CPU0_GTL_TDI")
	)
	(segment
		(start 208.446878 -192.724024)
		(end 207.955896 -192.724024)
		(width 0.12954)
		(layer "B.Cu")
		(net "JTAG_MUX_CPU0_GTL_TDI")
	)
	(segment
		(start 338.63788 -186.020202)
		(end 337.903312 -186.75477)
		(width 0.12954)
		(layer "B.Cu")
		(net "JTAG_MUX_CPU0_GTL_TDI")
	)
	(segment
		(start 326.85228 -167.731948)
		(end 338.63788 -179.517548)
		(width 0.12954)
		(layer "B.Cu")
		(net "JTAG_MUX_CPU0_GTL_TDI")
	)
	(segment
		(start 338.911692 -187.598558)
		(end 337.905852 -187.598558)
		(width 0.12954)
		(layer "B.Cu")
		(net "JTAG_MUX_CPU0_GTL_TDI")
	)
	(segment
		(start 337.903312 -186.75477)
		(end 337.903312 -187.596018)
		(width 0.12954)
		(layer "B.Cu")
		(net "JTAG_MUX_CPU0_GTL_TDI")
	)
	(segment
		(start 338.63788 -179.517548)
		(end 338.63788 -186.020202)
		(width 0.12954)
		(layer "B.Cu")
		(net "JTAG_MUX_CPU0_GTL_TDI")
	)
	(segment
		(start 290.78174 -155.895548)
		(end 291.24402 -156.357828)
		(width 0.12954)
		(layer "B.Cu")
		(net "JTAG_MUX_CPU0_GTL_TDI")
	)
	(segment
		(start 208.882996 -192.287906)
		(end 208.446878 -192.724024)
		(width 0.12954)
		(layer "B.Cu")
		(net "JTAG_MUX_CPU0_GTL_TDI")
	)
	(segment
		(start 309.22976 -156.357828)
		(end 320.60388 -167.731948)
		(width 0.12954)
		(layer "B.Cu")
		(net "JTAG_MUX_CPU0_GTL_TDI")
	)
	(segment
		(start 225.22688 -188.443108)
		(end 225.13036 -188.539628)
		(width 0.127)
		(layer "In13.Cu")
		(net "JTAG_MUX_CPU0_GTL_TDI")
	)
	(segment
		(start 215.33104 -193.327528)
		(end 214.33282 -193.327528)
		(width 0.127)
		(layer "In13.Cu")
		(net "JTAG_MUX_CPU0_GTL_TDI")
	)
	(segment
		(start 213.67242 -193.987928)
		(end 213.1568 -193.987928)
		(width 0.127)
		(layer "In13.Cu")
		(net "JTAG_MUX_CPU0_GTL_TDI")
	)
	(segment
		(start 208.882996 -192.294764)
		(end 208.882996 -192.287906)
		(width 0.127)
		(layer "In13.Cu")
		(net "JTAG_MUX_CPU0_GTL_TDI")
	)
	(segment
		(start 213.1568 -193.987928)
		(end 212.8774 -194.267328)
		(width 0.127)
		(layer "In13.Cu")
		(net "JTAG_MUX_CPU0_GTL_TDI")
	)
	(segment
		(start 214.33282 -193.327528)
		(end 213.67242 -193.987928)
		(width 0.127)
		(layer "In13.Cu")
		(net "JTAG_MUX_CPU0_GTL_TDI")
	)
	(segment
		(start 212.8774 -194.267328)
		(end 210.85556 -194.267328)
		(width 0.127)
		(layer "In13.Cu")
		(net "JTAG_MUX_CPU0_GTL_TDI")
	)
	(segment
		(start 210.85556 -194.267328)
		(end 208.882996 -192.294764)
		(width 0.127)
		(layer "In13.Cu")
		(net "JTAG_MUX_CPU0_GTL_TDI")
	)
	(segment
		(start 215.99144 -193.987928)
		(end 215.33104 -193.327528)
		(width 0.127)
		(layer "In13.Cu")
		(net "JTAG_MUX_CPU0_GTL_TDI")
	)
	(segment
		(start 225.13036 -188.539628)
		(end 225.13036 -190.255652)
		(width 0.127)
		(layer "In13.Cu")
		(net "JTAG_MUX_CPU0_GTL_TDI")
	)
	(segment
		(start 225.13036 -190.255652)
		(end 221.398084 -193.987928)
		(width 0.127)
		(layer "In13.Cu")
		(net "JTAG_MUX_CPU0_GTL_TDI")
	)
	(segment
		(start 221.398084 -193.987928)
		(end 215.99144 -193.987928)
		(width 0.127)
		(layer "In13.Cu")
		(net "JTAG_MUX_CPU0_GTL_TDI")
	)
	(segment
		(start 396.2146 -66.335148)
		(end 396.2146 -64.419988)
		(width 0.12954)
		(layer "F.Cu")
		(net "JTAG_DBP_TMS_R")
	)
	(segment
		(start 396.38478 -64.249808)
		(end 397.765016 -64.249808)
		(width 0.12954)
		(layer "F.Cu")
		(net "JTAG_DBP_TMS_R")
	)
	(segment
		(start 390.9441 -67.851528)
		(end 394.69822 -67.851528)
		(width 0.12954)
		(layer "F.Cu")
		(net "JTAG_DBP_TMS_R")
	)
	(segment
		(start 394.69822 -67.851528)
		(end 396.2146 -66.335148)
		(width 0.12954)
		(layer "F.Cu")
		(net "JTAG_DBP_TMS_R")
	)
	(segment
		(start 389.61568 -69.179948)
		(end 390.9441 -67.851528)
		(width 0.12954)
		(layer "F.Cu")
		(net "JTAG_DBP_TMS_R")
	)
	(segment
		(start 386.09905 -69.179948)
		(end 389.61568 -69.179948)
		(width 0.12954)
		(layer "F.Cu")
		(net "JTAG_DBP_TMS_R")
	)
	(segment
		(start 396.2146 -64.419988)
		(end 396.38478 -64.249808)
		(width 0.12954)
		(layer "F.Cu")
		(net "JTAG_DBP_TMS_R")
	)
	(via
		(at 390.9441 -67.851528)
		(size 0.508)
		(drill 0.254)
		(layers "F.Cu" "B.Cu")
		(net "JTAG_DBP_TMS_R")
	)
	(segment
		(start 349.164402 -22.40026)
		(end 349.164402 -26.441146)
		(width 0.12954)
		(layer "F.Cu")
		(net "JTAG_DBP_TMS_PCH")
	)
	(segment
		(start 348.196154 -29.588206)
		(end 347.176344 -30.608016)
		(width 0.12954)
		(layer "F.Cu")
		(net "JTAG_DBP_TMS_PCH")
	)
	(segment
		(start 348.196154 -27.409394)
		(end 348.196154 -29.588206)
		(width 0.12954)
		(layer "F.Cu")
		(net "JTAG_DBP_TMS_PCH")
	)
	(segment
		(start 344.149426 -37.232844)
		(end 344.182192 -37.39769)
		(width 0.0889)
		(layer "F.Cu")
		(net "JTAG_DBP_TMS_PCH")
	)
	(segment
		(start 367.6523 -38.344348)
		(end 367.335308 -38.027356)
		(width 0.12954)
		(layer "F.Cu")
		(net "JTAG_DBP_TMS_PCH")
	)
	(segment
		(start 347.176344 -30.608016)
		(end 347.176344 -34.325306)
		(width 0.12954)
		(layer "F.Cu")
		(net "JTAG_DBP_TMS_PCH")
	)
	(segment
		(start 367.335308 -33.770824)
		(end 354.916232 -21.351748)
		(width 0.12954)
		(layer "F.Cu")
		(net "JTAG_DBP_TMS_PCH")
	)
	(segment
		(start 369.8621 -54.453028)
		(end 370.7892 -54.453028)
		(width 0.12954)
		(layer "F.Cu")
		(net "JTAG_DBP_TMS_PCH")
	)
	(segment
		(start 372.434866 -51.354736)
		(end 372.434866 -39.248334)
		(width 0.12954)
		(layer "F.Cu")
		(net "JTAG_DBP_TMS_PCH")
	)
	(segment
		(start 354.916232 -21.351748)
		(end 350.212914 -21.351748)
		(width 0.12954)
		(layer "F.Cu")
		(net "JTAG_DBP_TMS_PCH")
	)
	(segment
		(start 370.7892 -54.453028)
		(end 372.150894 -53.091334)
		(width 0.12954)
		(layer "F.Cu")
		(net "JTAG_DBP_TMS_PCH")
	)
	(segment
		(start 350.212914 -21.351748)
		(end 349.164402 -22.40026)
		(width 0.12954)
		(layer "F.Cu")
		(net "JTAG_DBP_TMS_PCH")
	)
	(segment
		(start 367.81105 -53.812948)
		(end 369.22202 -53.812948)
		(width 0.12954)
		(layer "F.Cu")
		(net "JTAG_DBP_TMS_PCH")
	)
	(segment
		(start 371.60962 -38.423088)
		(end 369.9637 -38.423088)
		(width 0.12954)
		(layer "F.Cu")
		(net "JTAG_DBP_TMS_PCH")
	)
	(segment
		(start 344.149426 -36.917376)
		(end 344.149426 -37.232844)
		(width 0.0889)
		(layer "F.Cu")
		(net "JTAG_DBP_TMS_PCH")
	)
	(segment
		(start 369.9637 -38.423088)
		(end 369.88496 -38.344348)
		(width 0.12954)
		(layer "F.Cu")
		(net "JTAG_DBP_TMS_PCH")
	)
	(segment
		(start 349.164402 -26.441146)
		(end 348.196154 -27.409394)
		(width 0.12954)
		(layer "F.Cu")
		(net "JTAG_DBP_TMS_PCH")
	)
	(segment
		(start 344.092022 -38.123622)
		(end 344.1319 -38.230556)
		(width 0.0889)
		(layer "F.Cu")
		(net "JTAG_DBP_TMS_PCH")
	)
	(segment
		(start 344.1319 -38.230556)
		(end 344.231214 -38.345618)
		(width 0.0889)
		(layer "F.Cu")
		(net "JTAG_DBP_TMS_PCH")
	)
	(segment
		(start 344.40368 -38.518084)
		(end 344.40368 -38.880034)
		(width 0.0889)
		(layer "F.Cu")
		(net "JTAG_DBP_TMS_PCH")
	)
	(segment
		(start 367.335308 -38.027356)
		(end 367.335308 -33.770824)
		(width 0.12954)
		(layer "F.Cu")
		(net "JTAG_DBP_TMS_PCH")
	)
	(segment
		(start 346.465906 -35.035744)
		(end 346.347542 -35.154108)
		(width 0.0889)
		(layer "F.Cu")
		(net "JTAG_DBP_TMS_PCH")
	)
	(segment
		(start 344.182192 -37.39769)
		(end 344.182192 -37.841428)
		(width 0.0889)
		(layer "F.Cu")
		(net "JTAG_DBP_TMS_PCH")
	)
	(segment
		(start 344.092022 -37.931598)
		(end 344.092022 -38.123622)
		(width 0.0889)
		(layer "F.Cu")
		(net "JTAG_DBP_TMS_PCH")
	)
	(segment
		(start 372.434866 -39.248334)
		(end 371.60962 -38.423088)
		(width 0.12954)
		(layer "F.Cu")
		(net "JTAG_DBP_TMS_PCH")
	)
	(segment
		(start 344.231214 -38.345618)
		(end 344.40368 -38.518084)
		(width 0.0889)
		(layer "F.Cu")
		(net "JTAG_DBP_TMS_PCH")
	)
	(segment
		(start 344.40368 -38.880034)
		(end 344.403426 -38.880288)
		(width 0.0889)
		(layer "F.Cu")
		(net "JTAG_DBP_TMS_PCH")
	)
	(segment
		(start 369.88496 -38.344348)
		(end 367.6523 -38.344348)
		(width 0.12954)
		(layer "F.Cu")
		(net "JTAG_DBP_TMS_PCH")
	)
	(segment
		(start 344.182192 -37.841428)
		(end 344.092022 -37.931598)
		(width 0.0889)
		(layer "F.Cu")
		(net "JTAG_DBP_TMS_PCH")
	)
	(segment
		(start 345.912694 -35.154108)
		(end 344.149426 -36.917376)
		(width 0.0889)
		(layer "F.Cu")
		(net "JTAG_DBP_TMS_PCH")
	)
	(segment
		(start 372.150894 -51.638708)
		(end 372.434866 -51.354736)
		(width 0.12954)
		(layer "F.Cu")
		(net "JTAG_DBP_TMS_PCH")
	)
	(segment
		(start 346.347542 -35.154108)
		(end 345.912694 -35.154108)
		(width 0.0889)
		(layer "F.Cu")
		(net "JTAG_DBP_TMS_PCH")
	)
	(segment
		(start 347.176344 -34.325306)
		(end 346.465906 -35.035744)
		(width 0.12954)
		(layer "F.Cu")
		(net "JTAG_DBP_TMS_PCH")
	)
	(segment
		(start 369.22202 -53.812948)
		(end 369.8621 -54.453028)
		(width 0.12954)
		(layer "F.Cu")
		(net "JTAG_DBP_TMS_PCH")
	)
	(segment
		(start 372.150894 -53.091334)
		(end 372.150894 -51.638708)
		(width 0.12954)
		(layer "F.Cu")
		(net "JTAG_DBP_TMS_PCH")
	)
	(segment
		(start 367.81105 -53.812948)
		(end 367.81105 -54.828948)
		(width 0.12954)
		(layer "F.Cu")
		(net "JTAG_DBP_TMS_PCH")
	)
	(via
		(at 359.49636 -58.880248)
		(size 0.508)
		(drill 0.254)
		(layers "F.Cu" "B.Cu")
		(net "JTAG_DBP_TMS_PCH")
	)
	(via
		(at 369.8621 -54.453028)
		(size 0.508)
		(drill 0.254)
		(layers "F.Cu" "B.Cu")
		(net "JTAG_DBP_TMS_PCH")
	)
	(segment
		(start 369.8621 -54.453028)
		(end 367.67262 -54.453028)
		(width 0.127)
		(layer "In2.Cu")
		(net "JTAG_DBP_TMS_PCH")
	)
	(segment
		(start 360.796332 -58.880248)
		(end 359.49636 -58.880248)
		(width 0.127)
		(layer "In2.Cu")
		(net "JTAG_DBP_TMS_PCH")
	)
	(segment
		(start 367.67262 -54.453028)
		(end 365.5187 -56.606948)
		(width 0.127)
		(layer "In2.Cu")
		(net "JTAG_DBP_TMS_PCH")
	)
	(segment
		(start 365.5187 -56.606948)
		(end 363.069632 -56.606948)
		(width 0.127)
		(layer "In2.Cu")
		(net "JTAG_DBP_TMS_PCH")
	)
	(segment
		(start 363.069632 -56.606948)
		(end 360.796332 -58.880248)
		(width 0.127)
		(layer "In2.Cu")
		(net "JTAG_DBP_TMS_PCH")
	)
	(segment
		(start 368.554 -60.543948)
		(end 366.92332 -60.543948)
		(width 0.12954)
		(layer "F.Cu")
		(net "JTAG_DBP_TMS")
	)
	(segment
		(start 363.601 -61.356748)
		(end 362.839 -60.594748)
		(width 0.12954)
		(layer "F.Cu")
		(net "JTAG_DBP_TMS")
	)
	(segment
		(start 384.24358 -69.179948)
		(end 378.12726 -63.063628)
		(width 0.12954)
		(layer "F.Cu")
		(net "JTAG_DBP_TMS")
	)
	(segment
		(start 378.12726 -63.063628)
		(end 370.60124 -63.063628)
		(width 0.12954)
		(layer "F.Cu")
		(net "JTAG_DBP_TMS")
	)
	(segment
		(start 373.577358 -91.429586)
		(end 373.577358 -92.562934)
		(width 0.12954)
		(layer "F.Cu")
		(net "JTAG_DBP_TMS")
	)
	(segment
		(start 364.841282 -59.833764)
		(end 363.295184 -59.833764)
		(width 0.12954)
		(layer "F.Cu")
		(net "JTAG_DBP_TMS")
	)
	(segment
		(start 368.89436 -61.356748)
		(end 363.601 -61.356748)
		(width 0.12954)
		(layer "F.Cu")
		(net "JTAG_DBP_TMS")
	)
	(segment
		(start 362.839 -60.289948)
		(end 363.295184 -59.833764)
		(width 0.12954)
		(layer "F.Cu")
		(net "JTAG_DBP_TMS")
	)
	(segment
		(start 385.29895 -69.179948)
		(end 384.24358 -69.179948)
		(width 0.12954)
		(layer "F.Cu")
		(net "JTAG_DBP_TMS")
	)
	(segment
		(start 362.839 -60.594748)
		(end 362.839 -60.289948)
		(width 0.12954)
		(layer "F.Cu")
		(net "JTAG_DBP_TMS")
	)
	(segment
		(start 366.92078 -60.546488)
		(end 366.208056 -59.833764)
		(width 0.12954)
		(layer "F.Cu")
		(net "JTAG_DBP_TMS")
	)
	(segment
		(start 366.208056 -59.833764)
		(end 364.841282 -59.833764)
		(width 0.12954)
		(layer "F.Cu")
		(net "JTAG_DBP_TMS")
	)
	(segment
		(start 367.01095 -55.571898)
		(end 368.935 -57.495948)
		(width 0.12954)
		(layer "F.Cu")
		(net "JTAG_DBP_TMS")
	)
	(segment
		(start 368.935 -60.162948)
		(end 368.554 -60.543948)
		(width 0.12954)
		(layer "F.Cu")
		(net "JTAG_DBP_TMS")
	)
	(segment
		(start 367.01095 -54.828948)
		(end 367.01095 -55.571898)
		(width 0.12954)
		(layer "F.Cu")
		(net "JTAG_DBP_TMS")
	)
	(segment
		(start 368.935 -57.495948)
		(end 368.935 -60.162948)
		(width 0.12954)
		(layer "F.Cu")
		(net "JTAG_DBP_TMS")
	)
	(segment
		(start 371.56898 -90.173048)
		(end 372.32082 -90.173048)
		(width 0.12954)
		(layer "F.Cu")
		(net "JTAG_DBP_TMS")
	)
	(segment
		(start 372.32082 -90.173048)
		(end 373.577358 -91.429586)
		(width 0.12954)
		(layer "F.Cu")
		(net "JTAG_DBP_TMS")
	)
	(segment
		(start 366.92332 -60.543948)
		(end 366.92078 -60.546488)
		(width 0.12954)
		(layer "F.Cu")
		(net "JTAG_DBP_TMS")
	)
	(segment
		(start 370.60124 -63.063628)
		(end 368.89436 -61.356748)
		(width 0.12954)
		(layer "F.Cu")
		(net "JTAG_DBP_TMS")
	)
	(via
		(at 371.56898 -90.173048)
		(size 0.508)
		(drill 0.254)
		(layers "F.Cu" "B.Cu")
		(net "JTAG_DBP_TMS")
	)
	(via
		(at 366.92078 -60.546488)
		(size 0.508)
		(drill 0.254)
		(layers "F.Cu" "B.Cu")
		(net "JTAG_DBP_TMS")
	)
	(segment
		(start 370.115084 -90.173048)
		(end 366.98936 -87.047324)
		(width 0.127)
		(layer "In2.Cu")
		(net "JTAG_DBP_TMS")
	)
	(segment
		(start 366.98936 -60.615068)
		(end 366.92078 -60.546488)
		(width 0.127)
		(layer "In2.Cu")
		(net "JTAG_DBP_TMS")
	)
	(segment
		(start 366.98936 -87.047324)
		(end 366.98936 -60.615068)
		(width 0.127)
		(layer "In2.Cu")
		(net "JTAG_DBP_TMS")
	)
	(segment
		(start 371.56898 -90.173048)
		(end 370.115084 -90.173048)
		(width 0.127)
		(layer "In2.Cu")
		(net "JTAG_DBP_TMS")
	)
	(segment
		(start 395.85392 -66.086228)
		(end 395.85392 -64.064388)
		(width 0.12954)
		(layer "F.Cu")
		(net "JTAG_DBP_TDO_R")
	)
	(segment
		(start 388.90194 -67.274948)
		(end 394.6652 -67.274948)
		(width 0.12954)
		(layer "F.Cu")
		(net "JTAG_DBP_TDO_R")
	)
	(segment
		(start 386.134102 -68.126356)
		(end 386.823712 -68.126356)
		(width 0.12954)
		(layer "F.Cu")
		(net "JTAG_DBP_TDO_R")
	)
	(segment
		(start 386.823712 -68.126356)
		(end 387.67512 -67.274948)
		(width 0.12954)
		(layer "F.Cu")
		(net "JTAG_DBP_TDO_R")
	)
	(segment
		(start 395.85392 -64.064388)
		(end 396.168372 -63.749936)
		(width 0.12954)
		(layer "F.Cu")
		(net "JTAG_DBP_TDO_R")
	)
	(segment
		(start 387.67512 -67.274948)
		(end 388.90194 -67.274948)
		(width 0.12954)
		(layer "F.Cu")
		(net "JTAG_DBP_TDO_R")
	)
	(segment
		(start 394.6652 -67.274948)
		(end 395.85392 -66.086228)
		(width 0.12954)
		(layer "F.Cu")
		(net "JTAG_DBP_TDO_R")
	)
	(segment
		(start 396.168372 -63.749936)
		(end 397.765016 -63.749936)
		(width 0.12954)
		(layer "F.Cu")
		(net "JTAG_DBP_TDO_R")
	)
	(via
		(at 388.90194 -67.274948)
		(size 0.508)
		(drill 0.254)
		(layers "F.Cu" "B.Cu")
		(net "JTAG_DBP_TDO_R")
	)
	(segment
		(start 348.436946 -25.069038)
		(end 348.177866 -25.069038)
		(width 0.12954)
		(layer "F.Cu")
		(net "JTAG_DBP_TDO_PCH")
	)
	(segment
		(start 343.903046 -38.465252)
		(end 343.903046 -38.180772)
		(width 0.0889)
		(layer "F.Cu")
		(net "JTAG_DBP_TDO_PCH")
	)
	(segment
		(start 348.803976 -25.436068)
		(end 348.436946 -25.069038)
		(width 0.12954)
		(layer "F.Cu")
		(net "JTAG_DBP_TDO_PCH")
	)
	(segment
		(start 347.800676 -27.276552)
		(end 348.803976 -26.273252)
		(width 0.12954)
		(layer "F.Cu")
		(net "JTAG_DBP_TDO_PCH")
	)
	(segment
		(start 374.512332 -59.295792)
		(end 377.141232 -59.295792)
		(width 0.12954)
		(layer "F.Cu")
		(net "JTAG_DBP_TDO_PCH")
	)
	(segment
		(start 377.141232 -58.23458)
		(end 377.141232 -59.295792)
		(width 0.12954)
		(layer "F.Cu")
		(net "JTAG_DBP_TDO_PCH")
	)
	(segment
		(start 348.803976 -26.273252)
		(end 348.803976 -25.436068)
		(width 0.12954)
		(layer "F.Cu")
		(net "JTAG_DBP_TDO_PCH")
	)
	(segment
		(start 347.800676 -28.194508)
		(end 347.800676 -27.276552)
		(width 0.12954)
		(layer "F.Cu")
		(net "JTAG_DBP_TDO_PCH")
	)
	(segment
		(start 347.662754 -28.33243)
		(end 347.800676 -28.194508)
		(width 0.12954)
		(layer "F.Cu")
		(net "JTAG_DBP_TDO_PCH")
	)
	(segment
		(start 347.930724 -24.19858)
		(end 348.097856 -24.031448)
		(width 0.12954)
		(layer "F.Cu")
		(net "JTAG_DBP_TDO_PCH")
	)
	(segment
		(start 348.097856 -22.635972)
		(end 349.76308 -20.970748)
		(width 0.12954)
		(layer "F.Cu")
		(net "JTAG_DBP_TDO_PCH")
	)
	(segment
		(start 372.811294 -53.904642)
		(end 377.141232 -58.23458)
		(width 0.12954)
		(layer "F.Cu")
		(net "JTAG_DBP_TDO_PCH")
	)
	(segment
		(start 372.811294 -52.319428)
		(end 372.811294 -53.904642)
		(width 0.12954)
		(layer "F.Cu")
		(net "JTAG_DBP_TDO_PCH")
	)
	(segment
		(start 346.460064 -33.919922)
		(end 346.460064 -30.310836)
		(width 0.12954)
		(layer "F.Cu")
		(net "JTAG_DBP_TDO_PCH")
	)
	(segment
		(start 343.903046 -38.180772)
		(end 343.791794 -38.06952)
		(width 0.0889)
		(layer "F.Cu")
		(net "JTAG_DBP_TDO_PCH")
	)
	(segment
		(start 343.66327 -36.716716)
		(end 346.460064 -33.919922)
		(width 0.0889)
		(layer "F.Cu")
		(net "JTAG_DBP_TDO_PCH")
	)
	(segment
		(start 347.930724 -24.821896)
		(end 347.930724 -24.19858)
		(width 0.12954)
		(layer "F.Cu")
		(net "JTAG_DBP_TDO_PCH")
	)
	(segment
		(start 346.930726 -28.728162)
		(end 347.262958 -28.39593)
		(width 0.12954)
		(layer "F.Cu")
		(net "JTAG_DBP_TDO_PCH")
	)
	(segment
		(start 348.177866 -25.069038)
		(end 347.930724 -24.821896)
		(width 0.12954)
		(layer "F.Cu")
		(net "JTAG_DBP_TDO_PCH")
	)
	(segment
		(start 343.626948 -37.768784)
		(end 343.626948 -37.508434)
		(width 0.0889)
		(layer "F.Cu")
		(net "JTAG_DBP_TDO_PCH")
	)
	(segment
		(start 346.930726 -29.840174)
		(end 346.930726 -28.728162)
		(width 0.12954)
		(layer "F.Cu")
		(net "JTAG_DBP_TDO_PCH")
	)
	(segment
		(start 349.76308 -20.970748)
		(end 355.37394 -20.970748)
		(width 0.12954)
		(layer "F.Cu")
		(net "JTAG_DBP_TDO_PCH")
	)
	(segment
		(start 371.17528 -36.772088)
		(end 371.17528 -37.353748)
		(width 0.12954)
		(layer "F.Cu")
		(net "JTAG_DBP_TDO_PCH")
	)
	(segment
		(start 343.791794 -38.06952)
		(end 343.791794 -38.01618)
		(width 0.0889)
		(layer "F.Cu")
		(net "JTAG_DBP_TDO_PCH")
	)
	(segment
		(start 343.626948 -37.508434)
		(end 343.66327 -37.38499)
		(width 0.0889)
		(layer "F.Cu")
		(net "JTAG_DBP_TDO_PCH")
	)
	(segment
		(start 371.17528 -37.353748)
		(end 372.811294 -38.989762)
		(width 0.12954)
		(layer "F.Cu")
		(net "JTAG_DBP_TDO_PCH")
	)
	(segment
		(start 348.097856 -24.031448)
		(end 348.097856 -22.635972)
		(width 0.12954)
		(layer "F.Cu")
		(net "JTAG_DBP_TDO_PCH")
	)
	(segment
		(start 347.262958 -28.39593)
		(end 347.41612 -28.33243)
		(width 0.12954)
		(layer "F.Cu")
		(net "JTAG_DBP_TDO_PCH")
	)
	(segment
		(start 372.811294 -38.989762)
		(end 372.811294 -52.319428)
		(width 0.12954)
		(layer "F.Cu")
		(net "JTAG_DBP_TDO_PCH")
	)
	(segment
		(start 343.66327 -37.38499)
		(end 343.66327 -36.716716)
		(width 0.0889)
		(layer "F.Cu")
		(net "JTAG_DBP_TDO_PCH")
	)
	(segment
		(start 346.460064 -30.310836)
		(end 346.930726 -29.840174)
		(width 0.12954)
		(layer "F.Cu")
		(net "JTAG_DBP_TDO_PCH")
	)
	(segment
		(start 355.37394 -20.970748)
		(end 371.17528 -36.772088)
		(width 0.12954)
		(layer "F.Cu")
		(net "JTAG_DBP_TDO_PCH")
	)
	(segment
		(start 347.41612 -28.33243)
		(end 347.662754 -28.33243)
		(width 0.12954)
		(layer "F.Cu")
		(net "JTAG_DBP_TDO_PCH")
	)
	(segment
		(start 343.791794 -38.01618)
		(end 343.626948 -37.768784)
		(width 0.0889)
		(layer "F.Cu")
		(net "JTAG_DBP_TDO_PCH")
	)
	(via
		(at 372.811294 -52.319428)
		(size 0.508)
		(drill 0.254)
		(layers "F.Cu" "B.Cu")
		(net "JTAG_DBP_TDO_PCH")
	)
	(segment
		(start 385.334002 -68.126356)
		(end 383.86766 -68.126356)
		(width 0.12954)
		(layer "F.Cu")
		(net "JTAG_DBP_TDO")
	)
	(segment
		(start 373.291608 -59.295792)
		(end 373.179594 -59.183778)
		(width 0.12954)
		(layer "F.Cu")
		(net "JTAG_DBP_TDO")
	)
	(segment
		(start 373.712232 -58.58256)
		(end 373.712232 -59.295792)
		(width 0.12954)
		(layer "F.Cu")
		(net "JTAG_DBP_TDO")
	)
	(segment
		(start 378.322332 -62.581028)
		(end 374.9802 -62.581028)
		(width 0.12954)
		(layer "F.Cu")
		(net "JTAG_DBP_TDO")
	)
	(segment
		(start 374.9802 -62.581028)
		(end 373.9261 -61.526928)
		(width 0.12954)
		(layer "F.Cu")
		(net "JTAG_DBP_TDO")
	)
	(segment
		(start 374.32742 -105.491534)
		(end 374.719088 -105.883202)
		(width 0.12954)
		(layer "F.Cu")
		(net "JTAG_DBP_TDO")
	)
	(segment
		(start 374.32742 -102.446328)
		(end 374.32742 -105.491534)
		(width 0.12954)
		(layer "F.Cu")
		(net "JTAG_DBP_TDO")
	)
	(segment
		(start 373.712232 -59.295792)
		(end 373.291608 -59.295792)
		(width 0.12954)
		(layer "F.Cu")
		(net "JTAG_DBP_TDO")
	)
	(segment
		(start 373.9261 -61.526928)
		(end 373.9261 -59.50966)
		(width 0.12954)
		(layer "F.Cu")
		(net "JTAG_DBP_TDO")
	)
	(segment
		(start 374.719088 -105.883202)
		(end 375.255536 -105.883202)
		(width 0.12954)
		(layer "F.Cu")
		(net "JTAG_DBP_TDO")
	)
	(segment
		(start 383.86766 -68.126356)
		(end 378.322332 -62.581028)
		(width 0.12954)
		(layer "F.Cu")
		(net "JTAG_DBP_TDO")
	)
	(segment
		(start 373.179594 -59.183778)
		(end 370.683282 -59.183778)
		(width 0.12954)
		(layer "F.Cu")
		(net "JTAG_DBP_TDO")
	)
	(segment
		(start 373.9261 -59.50966)
		(end 373.712232 -59.295792)
		(width 0.12954)
		(layer "F.Cu")
		(net "JTAG_DBP_TDO")
	)
	(segment
		(start 374.7135 -102.060248)
		(end 374.32742 -102.446328)
		(width 0.12954)
		(layer "F.Cu")
		(net "JTAG_DBP_TDO")
	)
	(via
		(at 374.7135 -102.060248)
		(size 0.508)
		(drill 0.254)
		(layers "F.Cu" "B.Cu")
		(net "JTAG_DBP_TDO")
	)
	(via
		(at 373.712232 -58.58256)
		(size 0.508)
		(drill 0.254)
		(layers "F.Cu" "B.Cu")
		(net "JTAG_DBP_TDO")
	)
	(segment
		(start 375.00306 -90.691208)
		(end 372.45544 -88.143588)
		(width 0.127)
		(layer "In2.Cu")
		(net "JTAG_DBP_TDO")
	)
	(segment
		(start 374.7135 -102.060248)
		(end 375.00306 -101.770688)
		(width 0.127)
		(layer "In2.Cu")
		(net "JTAG_DBP_TDO")
	)
	(segment
		(start 372.45544 -88.143588)
		(end 372.45544 -71.669148)
		(width 0.127)
		(layer "In2.Cu")
		(net "JTAG_DBP_TDO")
	)
	(segment
		(start 375.52884 -63.939928)
		(end 373.712232 -62.12332)
		(width 0.127)
		(layer "In2.Cu")
		(net "JTAG_DBP_TDO")
	)
	(segment
		(start 372.45544 -71.669148)
		(end 375.52884 -68.595748)
		(width 0.127)
		(layer "In2.Cu")
		(net "JTAG_DBP_TDO")
	)
	(segment
		(start 375.52884 -68.595748)
		(end 375.52884 -63.939928)
		(width 0.127)
		(layer "In2.Cu")
		(net "JTAG_DBP_TDO")
	)
	(segment
		(start 375.00306 -101.770688)
		(end 375.00306 -90.691208)
		(width 0.127)
		(layer "In2.Cu")
		(net "JTAG_DBP_TDO")
	)
	(segment
		(start 373.712232 -62.12332)
		(end 373.712232 -58.58256)
		(width 0.127)
		(layer "In2.Cu")
		(net "JTAG_DBP_TDO")
	)
	(segment
		(start 390.153398 -63.24981)
		(end 389.5471 -63.856108)
		(width 0.12954)
		(layer "F.Cu")
		(net "JTAG_DBP_TDI_R")
	)
	(segment
		(start 386.932678 -63.856108)
		(end 386.116322 -64.672464)
		(width 0.12954)
		(layer "F.Cu")
		(net "JTAG_DBP_TDI_R")
	)
	(segment
		(start 389.5471 -63.856108)
		(end 388.4041 -63.856108)
		(width 0.12954)
		(layer "F.Cu")
		(net "JTAG_DBP_TDI_R")
	)
	(segment
		(start 388.4041 -63.856108)
		(end 386.932678 -63.856108)
		(width 0.12954)
		(layer "F.Cu")
		(net "JTAG_DBP_TDI_R")
	)
	(segment
		(start 392.034776 -63.24981)
		(end 390.153398 -63.24981)
		(width 0.12954)
		(layer "F.Cu")
		(net "JTAG_DBP_TDI_R")
	)
	(via
		(at 388.4041 -63.856108)
		(size 0.762)
		(drill 0.381)
		(layers "F.Cu" "B.Cu")
		(net "JTAG_DBP_TDI_R")
	)
	(segment
		(start 366.4204 -33.869884)
		(end 355.731064 -23.180548)
		(width 0.12954)
		(layer "F.Cu")
		(net "JTAG_DBP_TDI_PCH")
	)
	(segment
		(start 349.880682 -26.9875)
		(end 349.027496 -27.840686)
		(width 0.12954)
		(layer "F.Cu")
		(net "JTAG_DBP_TDI_PCH")
	)
	(segment
		(start 346.034614 -35.946588)
		(end 345.373452 -36.60775)
		(width 0.12954)
		(layer "F.Cu")
		(net "JTAG_DBP_TDI_PCH")
	)
	(segment
		(start 361.012232 -57.898792)
		(end 358.637332 -57.898792)
		(width 0.12954)
		(layer "F.Cu")
		(net "JTAG_DBP_TDI_PCH")
	)
	(segment
		(start 370.8019 -40.637968)
		(end 369.85702 -40.637968)
		(width 0.12954)
		(layer "F.Cu")
		(net "JTAG_DBP_TDI_PCH")
	)
	(segment
		(start 368.28984 -40.447468)
		(end 368.09934 -40.637968)
		(width 0.12954)
		(layer "F.Cu")
		(net "JTAG_DBP_TDI_PCH")
	)
	(segment
		(start 367.24082 -40.637968)
		(end 366.4204 -39.817548)
		(width 0.12954)
		(layer "F.Cu")
		(net "JTAG_DBP_TDI_PCH")
	)
	(segment
		(start 355.731064 -23.180548)
		(end 351.747328 -23.180548)
		(width 0.12954)
		(layer "F.Cu")
		(net "JTAG_DBP_TDI_PCH")
	)
	(segment
		(start 345.373452 -36.60775)
		(end 345.298776 -36.682426)
		(width 0.0889)
		(layer "F.Cu")
		(net "JTAG_DBP_TDI_PCH")
	)
	(segment
		(start 370.830094 -53.449728)
		(end 370.830094 -50.47742)
		(width 0.12954)
		(layer "F.Cu")
		(net "JTAG_DBP_TDI_PCH")
	)
	(segment
		(start 368.09934 -40.637968)
		(end 367.24082 -40.637968)
		(width 0.12954)
		(layer "F.Cu")
		(net "JTAG_DBP_TDI_PCH")
	)
	(segment
		(start 358.637332 -57.697116)
		(end 358.637332 -57.898792)
		(width 0.12954)
		(layer "F.Cu")
		(net "JTAG_DBP_TDI_PCH")
	)
	(segment
		(start 366.4204 -39.817548)
		(end 366.4204 -33.869884)
		(width 0.12954)
		(layer "F.Cu")
		(net "JTAG_DBP_TDI_PCH")
	)
	(segment
		(start 351.747328 -23.180548)
		(end 349.880682 -25.047194)
		(width 0.12954)
		(layer "F.Cu")
		(net "JTAG_DBP_TDI_PCH")
	)
	(segment
		(start 369.85702 -40.637968)
		(end 369.66652 -40.447468)
		(width 0.12954)
		(layer "F.Cu")
		(net "JTAG_DBP_TDI_PCH")
	)
	(segment
		(start 370.830094 -50.47742)
		(end 371.64518 -49.662334)
		(width 0.12954)
		(layer "F.Cu")
		(net "JTAG_DBP_TDI_PCH")
	)
	(segment
		(start 371.64518 -49.662334)
		(end 371.64518 -41.481248)
		(width 0.12954)
		(layer "F.Cu")
		(net "JTAG_DBP_TDI_PCH")
	)
	(segment
		(start 348.03334 -34.801048)
		(end 346.8878 -35.946588)
		(width 0.12954)
		(layer "F.Cu")
		(net "JTAG_DBP_TDI_PCH")
	)
	(segment
		(start 344.903552 -38.153086)
		(end 344.903552 -38.465252)
		(width 0.0889)
		(layer "F.Cu")
		(net "JTAG_DBP_TDI_PCH")
	)
	(segment
		(start 349.880682 -25.047194)
		(end 349.880682 -26.9875)
		(width 0.12954)
		(layer "F.Cu")
		(net "JTAG_DBP_TDI_PCH")
	)
	(segment
		(start 345.298776 -36.682426)
		(end 345.298776 -37.722302)
		(width 0.0889)
		(layer "F.Cu")
		(net "JTAG_DBP_TDI_PCH")
	)
	(segment
		(start 369.66652 -40.447468)
		(end 368.28984 -40.447468)
		(width 0.12954)
		(layer "F.Cu")
		(net "JTAG_DBP_TDI_PCH")
	)
	(segment
		(start 349.027496 -30.033468)
		(end 348.03334 -31.027624)
		(width 0.12954)
		(layer "F.Cu")
		(net "JTAG_DBP_TDI_PCH")
	)
	(segment
		(start 344.906092 -38.147498)
		(end 344.903552 -38.153086)
		(width 0.0889)
		(layer "F.Cu")
		(net "JTAG_DBP_TDI_PCH")
	)
	(segment
		(start 371.64518 -41.481248)
		(end 370.8019 -40.637968)
		(width 0.12954)
		(layer "F.Cu")
		(net "JTAG_DBP_TDI_PCH")
	)
	(segment
		(start 359.1306 -57.203848)
		(end 358.637332 -57.697116)
		(width 0.12954)
		(layer "F.Cu")
		(net "JTAG_DBP_TDI_PCH")
	)
	(segment
		(start 348.03334 -31.027624)
		(end 348.03334 -34.801048)
		(width 0.12954)
		(layer "F.Cu")
		(net "JTAG_DBP_TDI_PCH")
	)
	(segment
		(start 345.298776 -37.722302)
		(end 344.906092 -38.147498)
		(width 0.0889)
		(layer "F.Cu")
		(net "JTAG_DBP_TDI_PCH")
	)
	(segment
		(start 346.8878 -35.946588)
		(end 346.034614 -35.946588)
		(width 0.12954)
		(layer "F.Cu")
		(net "JTAG_DBP_TDI_PCH")
	)
	(segment
		(start 349.027496 -27.840686)
		(end 349.027496 -30.033468)
		(width 0.12954)
		(layer "F.Cu")
		(net "JTAG_DBP_TDI_PCH")
	)
	(via
		(at 370.830094 -53.449728)
		(size 0.508)
		(drill 0.254)
		(layers "F.Cu" "B.Cu")
		(net "JTAG_DBP_TDI_PCH")
	)
	(via
		(at 359.1306 -57.203848)
		(size 0.508)
		(drill 0.254)
		(layers "F.Cu" "B.Cu")
		(net "JTAG_DBP_TDI_PCH")
	)
	(segment
		(start 368.474752 -53.812948)
		(end 365.61268 -56.67502)
		(width 0.127)
		(layer "In4.Cu")
		(net "JTAG_DBP_TDI_PCH")
	)
	(segment
		(start 370.466874 -53.812948)
		(end 368.474752 -53.812948)
		(width 0.127)
		(layer "In4.Cu")
		(net "JTAG_DBP_TDI_PCH")
	)
	(segment
		(start 370.830094 -53.449728)
		(end 370.466874 -53.812948)
		(width 0.127)
		(layer "In4.Cu")
		(net "JTAG_DBP_TDI_PCH")
	)
	(segment
		(start 362.65358 -57.77738)
		(end 362.458 -57.97296)
		(width 0.127)
		(layer "In4.Cu")
		(net "JTAG_DBP_TDI_PCH")
	)
	(segment
		(start 362.65358 -57.08142)
		(end 362.65358 -57.77738)
		(width 0.127)
		(layer "In4.Cu")
		(net "JTAG_DBP_TDI_PCH")
	)
	(segment
		(start 359.1306 -57.54878)
		(end 359.1306 -57.203848)
		(width 0.127)
		(layer "In4.Cu")
		(net "JTAG_DBP_TDI_PCH")
	)
	(segment
		(start 365.61268 -56.67502)
		(end 363.05998 -56.67502)
		(width 0.127)
		(layer "In4.Cu")
		(net "JTAG_DBP_TDI_PCH")
	)
	(segment
		(start 362.458 -57.97296)
		(end 359.55478 -57.97296)
		(width 0.127)
		(layer "In4.Cu")
		(net "JTAG_DBP_TDI_PCH")
	)
	(segment
		(start 359.55478 -57.97296)
		(end 359.1306 -57.54878)
		(width 0.127)
		(layer "In4.Cu")
		(net "JTAG_DBP_TDI_PCH")
	)
	(segment
		(start 363.05998 -56.67502)
		(end 362.65358 -57.08142)
		(width 0.127)
		(layer "In4.Cu")
		(net "JTAG_DBP_TDI_PCH")
	)
	(segment
		(start 371.54866 -91.196668)
		(end 372.561358 -92.209366)
		(width 0.12954)
		(layer "F.Cu")
		(net "JTAG_DBP_TDI")
	)
	(segment
		(start 372.561358 -92.209366)
		(end 372.561358 -92.562934)
		(width 0.12954)
		(layer "F.Cu")
		(net "JTAG_DBP_TDI")
	)
	(segment
		(start 361.827318 -57.883806)
		(end 364.841282 -57.883806)
		(width 0.12954)
		(layer "F.Cu")
		(net "JTAG_DBP_TDI")
	)
	(segment
		(start 383.449576 -64.672464)
		(end 385.316222 -64.672464)
		(width 0.12954)
		(layer "F.Cu")
		(net "JTAG_DBP_TDI")
	)
	(segment
		(start 362.514896 -57.196228)
		(end 361.827318 -57.883806)
		(width 0.12954)
		(layer "F.Cu")
		(net "JTAG_DBP_TDI")
	)
	(segment
		(start 363.25048 -57.196228)
		(end 362.514896 -57.196228)
		(width 0.12954)
		(layer "F.Cu")
		(net "JTAG_DBP_TDI")
	)
	(segment
		(start 382.24206 -63.464948)
		(end 383.449576 -64.672464)
		(width 0.12954)
		(layer "F.Cu")
		(net "JTAG_DBP_TDI")
	)
	(segment
		(start 361.812332 -57.898792)
		(end 361.827318 -57.883806)
		(width 0.12954)
		(layer "F.Cu")
		(net "JTAG_DBP_TDI")
	)
	(via
		(at 363.25048 -57.196228)
		(size 0.508)
		(drill 0.254)
		(layers "F.Cu" "B.Cu")
		(net "JTAG_DBP_TDI")
	)
	(via
		(at 371.54866 -91.196668)
		(size 0.508)
		(drill 0.254)
		(layers "F.Cu" "B.Cu")
		(net "JTAG_DBP_TDI")
	)
	(via
		(at 382.24206 -63.464948)
		(size 0.508)
		(drill 0.254)
		(layers "F.Cu" "B.Cu")
		(net "JTAG_DBP_TDI")
	)
	(segment
		(start 364.79734 -63.90386)
		(end 364.79734 -58.463688)
		(width 0.127)
		(layer "In2.Cu")
		(net "JTAG_DBP_TDI")
	)
	(segment
		(start 371.54866 -91.196668)
		(end 370.122704 -91.196668)
		(width 0.127)
		(layer "In2.Cu")
		(net "JTAG_DBP_TDI")
	)
	(segment
		(start 366.271048 -87.345012)
		(end 366.271048 -65.377568)
		(width 0.127)
		(layer "In2.Cu")
		(net "JTAG_DBP_TDI")
	)
	(segment
		(start 363.52988 -57.196228)
		(end 363.25048 -57.196228)
		(width 0.127)
		(layer "In2.Cu")
		(net "JTAG_DBP_TDI")
	)
	(segment
		(start 366.271048 -65.377568)
		(end 364.79734 -63.90386)
		(width 0.127)
		(layer "In2.Cu")
		(net "JTAG_DBP_TDI")
	)
	(segment
		(start 364.79734 -58.463688)
		(end 363.52988 -57.196228)
		(width 0.127)
		(layer "In2.Cu")
		(net "JTAG_DBP_TDI")
	)
	(segment
		(start 370.122704 -91.196668)
		(end 366.271048 -87.345012)
		(width 0.127)
		(layer "In2.Cu")
		(net "JTAG_DBP_TDI")
	)
	(segment
		(start 381.446786 -62.669674)
		(end 381.446786 -58.851292)
		(width 0.127)
		(layer "In4.Cu")
		(net "JTAG_DBP_TDI")
	)
	(segment
		(start 382.24206 -63.464948)
		(end 381.446786 -62.669674)
		(width 0.127)
		(layer "In4.Cu")
		(net "JTAG_DBP_TDI")
	)
	(segment
		(start 374.83288 -57.808368)
		(end 363.86262 -57.808368)
		(width 0.127)
		(layer "In4.Cu")
		(net "JTAG_DBP_TDI")
	)
	(segment
		(start 380.945136 -58.349642)
		(end 375.374154 -58.349642)
		(width 0.127)
		(layer "In4.Cu")
		(net "JTAG_DBP_TDI")
	)
	(segment
		(start 381.446786 -58.851292)
		(end 380.945136 -58.349642)
		(width 0.127)
		(layer "In4.Cu")
		(net "JTAG_DBP_TDI")
	)
	(segment
		(start 375.374154 -58.349642)
		(end 374.83288 -57.808368)
		(width 0.127)
		(layer "In4.Cu")
		(net "JTAG_DBP_TDI")
	)
	(segment
		(start 363.86262 -57.808368)
		(end 363.25048 -57.196228)
		(width 0.127)
		(layer "In4.Cu")
		(net "JTAG_DBP_TDI")
	)
	(segment
		(start 387.84022 -51.74996)
		(end 392.034776 -51.74996)
		(width 0.12954)
		(layer "F.Cu")
		(net "JTAG_DBP_TCK_R_TCK")
	)
	(segment
		(start 385.384802 -49.888648)
		(end 387.246114 -51.74996)
		(width 0.12954)
		(layer "F.Cu")
		(net "JTAG_DBP_TCK_R_TCK")
	)
	(segment
		(start 387.246114 -51.74996)
		(end 387.84022 -51.74996)
		(width 0.12954)
		(layer "F.Cu")
		(net "JTAG_DBP_TCK_R_TCK")
	)
	(via
		(at 387.84022 -51.74996)
		(size 0.762)
		(drill 0.381)
		(layers "F.Cu" "B.Cu")
		(net "JTAG_DBP_TCK_R_TCK")
	)
	(segment
		(start 108.306108 -53.327046)
		(end 108.328206 -53.304948)
		(width 0.12954)
		(layer "F.Cu")
		(net "JTAG_DBP_TCK_PCH_R")
	)
	(segment
		(start 107.49788 -53.327046)
		(end 108.306108 -53.327046)
		(width 0.12954)
		(layer "F.Cu")
		(net "JTAG_DBP_TCK_PCH_R")
	)
	(segment
		(start 108.328206 -53.304948)
		(end 108.74883 -53.304948)
		(width 0.12954)
		(layer "F.Cu")
		(net "JTAG_DBP_TCK_PCH_R")
	)
	(segment
		(start 105.76941 -53.327046)
		(end 107.49788 -53.327046)
		(width 0.12954)
		(layer "F.Cu")
		(net "JTAG_DBP_TCK_PCH_R")
	)
	(via
		(at 107.49788 -53.327046)
		(size 0.762)
		(drill 0.381)
		(layers "F.Cu" "B.Cu")
		(net "JTAG_DBP_TCK_PCH_R")
	)
	(segment
		(start 347.650562 -26.54935)
		(end 346.995496 -27.204416)
		(width 0.12954)
		(layer "F.Cu")
		(net "JTAG_DBP_TCK_PCH")
	)
	(segment
		(start 347.572584 -23.733506)
		(end 347.572584 -25.548082)
		(width 0.12954)
		(layer "F.Cu")
		(net "JTAG_DBP_TCK_PCH")
	)
	(segment
		(start 371.60708 -36.697158)
		(end 355.49967 -20.589748)
		(width 0.12954)
		(layer "F.Cu")
		(net "JTAG_DBP_TCK_PCH")
	)
	(segment
		(start 355.49967 -20.589748)
		(end 349.585026 -20.589748)
		(width 0.12954)
		(layer "F.Cu")
		(net "JTAG_DBP_TCK_PCH")
	)
	(segment
		(start 347.572584 -25.548082)
		(end 347.650562 -25.62606)
		(width 0.12954)
		(layer "F.Cu")
		(net "JTAG_DBP_TCK_PCH")
	)
	(segment
		(start 347.650562 -23.655528)
		(end 347.572584 -23.733506)
		(width 0.12954)
		(layer "F.Cu")
		(net "JTAG_DBP_TCK_PCH")
	)
	(segment
		(start 373.25808 -51.844194)
		(end 373.25808 -44.934378)
		(width 0.12954)
		(layer "F.Cu")
		(net "JTAG_DBP_TCK_PCH")
	)
	(segment
		(start 349.585026 -20.589748)
		(end 347.650562 -22.524212)
		(width 0.12954)
		(layer "F.Cu")
		(net "JTAG_DBP_TCK_PCH")
	)
	(segment
		(start 347.650562 -25.62606)
		(end 347.650562 -26.54935)
		(width 0.12954)
		(layer "F.Cu")
		(net "JTAG_DBP_TCK_PCH")
	)
	(segment
		(start 346.572586 -27.699716)
		(end 346.572586 -29.691584)
		(width 0.12954)
		(layer "F.Cu")
		(net "JTAG_DBP_TCK_PCH")
	)
	(segment
		(start 373.25808 -44.934378)
		(end 374.00865 -44.183808)
		(width 0.12954)
		(layer "F.Cu")
		(net "JTAG_DBP_TCK_PCH")
	)
	(segment
		(start 109.54893 -53.304948)
		(end 110.15853 -53.304948)
		(width 0.12954)
		(layer "F.Cu")
		(net "JTAG_DBP_TCK_PCH")
	)
	(segment
		(start 343.40292 -37.353748)
		(end 343.40292 -38.050216)
		(width 0.0889)
		(layer "F.Cu")
		(net "JTAG_DBP_TCK_PCH")
	)
	(segment
		(start 346.572586 -29.691584)
		(end 346.101924 -30.162246)
		(width 0.12954)
		(layer "F.Cu")
		(net "JTAG_DBP_TCK_PCH")
	)
	(segment
		(start 346.945204 -27.204416)
		(end 346.659454 -27.490166)
		(width 0.12954)
		(layer "F.Cu")
		(net "JTAG_DBP_TCK_PCH")
	)
	(segment
		(start 346.101924 -33.897062)
		(end 343.469722 -36.529264)
		(width 0.0889)
		(layer "F.Cu")
		(net "JTAG_DBP_TCK_PCH")
	)
	(segment
		(start 343.469722 -37.286946)
		(end 343.40292 -37.353748)
		(width 0.0889)
		(layer "F.Cu")
		(net "JTAG_DBP_TCK_PCH")
	)
	(segment
		(start 343.469722 -36.529264)
		(end 343.469722 -37.286946)
		(width 0.0889)
		(layer "F.Cu")
		(net "JTAG_DBP_TCK_PCH")
	)
	(segment
		(start 347.650562 -22.524212)
		(end 347.650562 -23.655528)
		(width 0.12954)
		(layer "F.Cu")
		(net "JTAG_DBP_TCK_PCH")
	)
	(segment
		(start 373.97309 -52.559204)
		(end 373.25808 -51.844194)
		(width 0.12954)
		(layer "F.Cu")
		(net "JTAG_DBP_TCK_PCH")
	)
	(segment
		(start 374.00865 -44.183808)
		(end 374.00865 -39.577772)
		(width 0.12954)
		(layer "F.Cu")
		(net "JTAG_DBP_TCK_PCH")
	)
	(segment
		(start 346.101924 -30.162246)
		(end 346.101924 -33.897062)
		(width 0.12954)
		(layer "F.Cu")
		(net "JTAG_DBP_TCK_PCH")
	)
	(segment
		(start 385.384802 -49.088548)
		(end 386.36321 -49.088548)
		(width 0.12954)
		(layer "F.Cu")
		(net "JTAG_DBP_TCK_PCH")
	)
	(segment
		(start 346.995496 -27.204416)
		(end 346.945204 -27.204416)
		(width 0.12954)
		(layer "F.Cu")
		(net "JTAG_DBP_TCK_PCH")
	)
	(segment
		(start 371.60708 -37.176202)
		(end 371.60708 -36.697158)
		(width 0.12954)
		(layer "F.Cu")
		(net "JTAG_DBP_TCK_PCH")
	)
	(segment
		(start 374.00865 -39.577772)
		(end 371.60708 -37.176202)
		(width 0.12954)
		(layer "F.Cu")
		(net "JTAG_DBP_TCK_PCH")
	)
	(segment
		(start 346.659454 -27.490166)
		(end 346.572586 -27.699716)
		(width 0.12954)
		(layer "F.Cu")
		(net "JTAG_DBP_TCK_PCH")
	)
	(segment
		(start 373.97309 -53.177948)
		(end 373.97309 -52.559204)
		(width 0.12954)
		(layer "F.Cu")
		(net "JTAG_DBP_TCK_PCH")
	)
	(via
		(at 216.6874 -28.895548)
		(size 0.508)
		(drill 0.254)
		(layers "F.Cu" "B.Cu")
		(net "JTAG_DBP_TCK_PCH")
	)
	(via
		(at 110.15853 -53.304948)
		(size 0.508)
		(drill 0.254)
		(layers "F.Cu" "B.Cu")
		(net "JTAG_DBP_TCK_PCH")
	)
	(via
		(at 262.694166 -32.754062)
		(size 0.508)
		(drill 0.254)
		(layers "F.Cu" "B.Cu")
		(net "JTAG_DBP_TCK_PCH")
	)
	(via
		(at 386.36321 -49.088548)
		(size 0.508)
		(drill 0.254)
		(layers "F.Cu" "B.Cu")
		(net "JTAG_DBP_TCK_PCH")
	)
	(via
		(at 373.97309 -53.177948)
		(size 0.508)
		(drill 0.254)
		(layers "F.Cu" "B.Cu")
		(net "JTAG_DBP_TCK_PCH")
	)
	(segment
		(start 217.113358 -36.885626)
		(end 221.62897 -36.885626)
		(width 0.12954)
		(layer "B.Cu")
		(net "JTAG_DBP_TCK_PCH")
	)
	(segment
		(start 386.36321 -49.088548)
		(end 378.60478 -49.088548)
		(width 0.12954)
		(layer "B.Cu")
		(net "JTAG_DBP_TCK_PCH")
	)
	(segment
		(start 259.90296 -36.556188)
		(end 262.694166 -33.764982)
		(width 0.12954)
		(layer "B.Cu")
		(net "JTAG_DBP_TCK_PCH")
	)
	(segment
		(start 216.6874 -28.895548)
		(end 216.29624 -29.286708)
		(width 0.12954)
		(layer "B.Cu")
		(net "JTAG_DBP_TCK_PCH")
	)
	(segment
		(start 256.616454 -38.60038)
		(end 259.387848 -38.60038)
		(width 0.12954)
		(layer "B.Cu")
		(net "JTAG_DBP_TCK_PCH")
	)
	(segment
		(start 216.29624 -29.286708)
		(end 216.29624 -36.068508)
		(width 0.12954)
		(layer "B.Cu")
		(net "JTAG_DBP_TCK_PCH")
	)
	(segment
		(start 230.293418 -37.901626)
		(end 233.345228 -40.953436)
		(width 0.12954)
		(layer "B.Cu")
		(net "JTAG_DBP_TCK_PCH")
	)
	(segment
		(start 253.942342 -39.715948)
		(end 255.500886 -39.715948)
		(width 0.12954)
		(layer "B.Cu")
		(net "JTAG_DBP_TCK_PCH")
	)
	(segment
		(start 241.91468 -42.154348)
		(end 242.54968 -42.789348)
		(width 0.12954)
		(layer "B.Cu")
		(net "JTAG_DBP_TCK_PCH")
	)
	(segment
		(start 259.90296 -38.085268)
		(end 259.90296 -36.556188)
		(width 0.12954)
		(layer "B.Cu")
		(net "JTAG_DBP_TCK_PCH")
	)
	(segment
		(start 255.500886 -39.715948)
		(end 256.616454 -38.60038)
		(width 0.12954)
		(layer "B.Cu")
		(net "JTAG_DBP_TCK_PCH")
	)
	(segment
		(start 374.46712 -53.226208)
		(end 374.02135 -53.226208)
		(width 0.12954)
		(layer "B.Cu")
		(net "JTAG_DBP_TCK_PCH")
	)
	(segment
		(start 248.72442 -40.583104)
		(end 253.075186 -40.583104)
		(width 0.12954)
		(layer "B.Cu")
		(net "JTAG_DBP_TCK_PCH")
	)
	(segment
		(start 374.02135 -53.226208)
		(end 373.97309 -53.177948)
		(width 0.12954)
		(layer "B.Cu")
		(net "JTAG_DBP_TCK_PCH")
	)
	(segment
		(start 221.62897 -36.885626)
		(end 222.64497 -37.901626)
		(width 0.12954)
		(layer "B.Cu")
		(net "JTAG_DBP_TCK_PCH")
	)
	(segment
		(start 216.29624 -36.068508)
		(end 217.113358 -36.885626)
		(width 0.12954)
		(layer "B.Cu")
		(net "JTAG_DBP_TCK_PCH")
	)
	(segment
		(start 378.60478 -49.088548)
		(end 374.46712 -53.226208)
		(width 0.12954)
		(layer "B.Cu")
		(net "JTAG_DBP_TCK_PCH")
	)
	(segment
		(start 236.244638 -42.154348)
		(end 241.91468 -42.154348)
		(width 0.12954)
		(layer "B.Cu")
		(net "JTAG_DBP_TCK_PCH")
	)
	(segment
		(start 233.345228 -40.953436)
		(end 236.244638 -42.154348)
		(width 0.12954)
		(layer "B.Cu")
		(net "JTAG_DBP_TCK_PCH")
	)
	(segment
		(start 259.387848 -38.60038)
		(end 259.90296 -38.085268)
		(width 0.12954)
		(layer "B.Cu")
		(net "JTAG_DBP_TCK_PCH")
	)
	(segment
		(start 222.64497 -37.901626)
		(end 230.293418 -37.901626)
		(width 0.12954)
		(layer "B.Cu")
		(net "JTAG_DBP_TCK_PCH")
	)
	(segment
		(start 262.694166 -33.764982)
		(end 262.694166 -32.754062)
		(width 0.12954)
		(layer "B.Cu")
		(net "JTAG_DBP_TCK_PCH")
	)
	(segment
		(start 253.075186 -40.583104)
		(end 253.942342 -39.715948)
		(width 0.12954)
		(layer "B.Cu")
		(net "JTAG_DBP_TCK_PCH")
	)
	(segment
		(start 242.54968 -42.789348)
		(end 246.518176 -42.789348)
		(width 0.12954)
		(layer "B.Cu")
		(net "JTAG_DBP_TCK_PCH")
	)
	(segment
		(start 246.518176 -42.789348)
		(end 248.72442 -40.583104)
		(width 0.12954)
		(layer "B.Cu")
		(net "JTAG_DBP_TCK_PCH")
	)
	(segment
		(start 262.694166 -32.754062)
		(end 263.01573 -32.432498)
		(width 0.127)
		(layer "In4.Cu")
		(net "JTAG_DBP_TCK_PCH")
	)
	(segment
		(start 111.43234 -52.031138)
		(end 110.15853 -53.304948)
		(width 0.127)
		(layer "In4.Cu")
		(net "JTAG_DBP_TCK_PCH")
	)
	(segment
		(start 213.445598 -28.038806)
		(end 213.031578 -28.038806)
		(width 0.127)
		(layer "In4.Cu")
		(net "JTAG_DBP_TCK_PCH")
	)
	(segment
		(start 195.55206 -15.512288)
		(end 194.31 -16.754348)
		(width 0.127)
		(layer "In4.Cu")
		(net "JTAG_DBP_TCK_PCH")
	)
	(segment
		(start 137.89914 -31.638748)
		(end 125.323092 -31.638748)
		(width 0.127)
		(layer "In4.Cu")
		(net "JTAG_DBP_TCK_PCH")
	)
	(segment
		(start 372.754652 -36.938712)
		(end 384.212084 -47.323248)
		(width 0.127)
		(layer "In4.Cu")
		(net "JTAG_DBP_TCK_PCH")
	)
	(segment
		(start 384.212084 -47.323248)
		(end 386.36321 -49.088548)
		(width 0.127)
		(layer "In4.Cu")
		(net "JTAG_DBP_TCK_PCH")
	)
	(segment
		(start 214.82558 -28.501848)
		(end 213.90864 -28.501848)
		(width 0.127)
		(layer "In4.Cu")
		(net "JTAG_DBP_TCK_PCH")
	)
	(segment
		(start 341.20074 -13.604748)
		(end 341.44966 -13.853668)
		(width 0.127)
		(layer "In4.Cu")
		(net "JTAG_DBP_TCK_PCH")
	)
	(segment
		(start 216.6874 -28.436316)
		(end 216.511632 -28.260548)
		(width 0.127)
		(layer "In4.Cu")
		(net "JTAG_DBP_TCK_PCH")
	)
	(segment
		(start 162.1028 -18.418048)
		(end 160.30702 -20.213828)
		(width 0.127)
		(layer "In4.Cu")
		(net "JTAG_DBP_TCK_PCH")
	)
	(segment
		(start 216.511632 -28.260548)
		(end 215.06688 -28.260548)
		(width 0.127)
		(layer "In4.Cu")
		(net "JTAG_DBP_TCK_PCH")
	)
	(segment
		(start 160.30702 -20.213828)
		(end 150.386288 -20.213828)
		(width 0.127)
		(layer "In4.Cu")
		(net "JTAG_DBP_TCK_PCH")
	)
	(segment
		(start 321.05346 -13.604748)
		(end 341.20074 -13.604748)
		(width 0.127)
		(layer "In4.Cu")
		(net "JTAG_DBP_TCK_PCH")
	)
	(segment
		(start 212.716364 -26.096722)
		(end 211.986114 -25.366472)
		(width 0.127)
		(layer "In4.Cu")
		(net "JTAG_DBP_TCK_PCH")
	)
	(segment
		(start 311.867296 -13.894308)
		(end 320.7639 -13.894308)
		(width 0.127)
		(layer "In4.Cu")
		(net "JTAG_DBP_TCK_PCH")
	)
	(segment
		(start 320.7639 -13.894308)
		(end 321.05346 -13.604748)
		(width 0.127)
		(layer "In4.Cu")
		(net "JTAG_DBP_TCK_PCH")
	)
	(segment
		(start 150.386288 -20.213828)
		(end 148.1836 -22.416516)
		(width 0.127)
		(layer "In4.Cu")
		(net "JTAG_DBP_TCK_PCH")
	)
	(segment
		(start 215.06688 -28.260548)
		(end 214.82558 -28.501848)
		(width 0.127)
		(layer "In4.Cu")
		(net "JTAG_DBP_TCK_PCH")
	)
	(segment
		(start 190.64986 -16.754348)
		(end 190.001652 -16.10614)
		(width 0.127)
		(layer "In4.Cu")
		(net "JTAG_DBP_TCK_PCH")
	)
	(segment
		(start 163.072572 -16.725392)
		(end 162.1028 -17.695164)
		(width 0.127)
		(layer "In4.Cu")
		(net "JTAG_DBP_TCK_PCH")
	)
	(segment
		(start 211.986114 -25.366472)
		(end 211.193634 -23.453344)
		(width 0.127)
		(layer "In4.Cu")
		(net "JTAG_DBP_TCK_PCH")
	)
	(segment
		(start 303.214786 -17.478248)
		(end 311.867296 -13.894308)
		(width 0.127)
		(layer "In4.Cu")
		(net "JTAG_DBP_TCK_PCH")
	)
	(segment
		(start 180.113432 -16.10614)
		(end 179.99456 -15.987268)
		(width 0.127)
		(layer "In4.Cu")
		(net "JTAG_DBP_TCK_PCH")
	)
	(segment
		(start 213.031578 -28.038806)
		(end 212.716364 -27.723592)
		(width 0.127)
		(layer "In4.Cu")
		(net "JTAG_DBP_TCK_PCH")
	)
	(segment
		(start 204.890116 -15.512288)
		(end 195.55206 -15.512288)
		(width 0.127)
		(layer "In4.Cu")
		(net "JTAG_DBP_TCK_PCH")
	)
	(segment
		(start 139.374372 -30.163516)
		(end 137.89914 -31.638748)
		(width 0.127)
		(layer "In4.Cu")
		(net "JTAG_DBP_TCK_PCH")
	)
	(segment
		(start 171.63034 -15.987268)
		(end 170.892216 -16.725392)
		(width 0.127)
		(layer "In4.Cu")
		(net "JTAG_DBP_TCK_PCH")
	)
	(segment
		(start 170.892216 -16.725392)
		(end 163.072572 -16.725392)
		(width 0.127)
		(layer "In4.Cu")
		(net "JTAG_DBP_TCK_PCH")
	)
	(segment
		(start 211.193634 -23.453344)
		(end 207.895952 -18.518124)
		(width 0.127)
		(layer "In4.Cu")
		(net "JTAG_DBP_TCK_PCH")
	)
	(segment
		(start 179.99456 -15.987268)
		(end 171.63034 -15.987268)
		(width 0.127)
		(layer "In4.Cu")
		(net "JTAG_DBP_TCK_PCH")
	)
	(segment
		(start 148.1836 -22.416516)
		(end 148.1836 -23.508208)
		(width 0.127)
		(layer "In4.Cu")
		(net "JTAG_DBP_TCK_PCH")
	)
	(segment
		(start 207.895952 -18.518124)
		(end 204.890116 -15.512288)
		(width 0.127)
		(layer "In4.Cu")
		(net "JTAG_DBP_TCK_PCH")
	)
	(segment
		(start 295.331388 -19.046444)
		(end 303.214786 -17.478248)
		(width 0.127)
		(layer "In4.Cu")
		(net "JTAG_DBP_TCK_PCH")
	)
	(segment
		(start 194.31 -16.754348)
		(end 190.64986 -16.754348)
		(width 0.127)
		(layer "In4.Cu")
		(net "JTAG_DBP_TCK_PCH")
	)
	(segment
		(start 216.6874 -28.895548)
		(end 216.6874 -28.436316)
		(width 0.127)
		(layer "In4.Cu")
		(net "JTAG_DBP_TCK_PCH")
	)
	(segment
		(start 349.669608 -13.853668)
		(end 372.754652 -36.938712)
		(width 0.127)
		(layer "In4.Cu")
		(net "JTAG_DBP_TCK_PCH")
	)
	(segment
		(start 341.44966 -13.853668)
		(end 349.669608 -13.853668)
		(width 0.127)
		(layer "In4.Cu")
		(net "JTAG_DBP_TCK_PCH")
	)
	(segment
		(start 263.01573 -32.432498)
		(end 295.331388 -19.046444)
		(width 0.127)
		(layer "In4.Cu")
		(net "JTAG_DBP_TCK_PCH")
	)
	(segment
		(start 125.323092 -31.638748)
		(end 111.43234 -45.5295)
		(width 0.127)
		(layer "In4.Cu")
		(net "JTAG_DBP_TCK_PCH")
	)
	(segment
		(start 190.001652 -16.10614)
		(end 180.113432 -16.10614)
		(width 0.127)
		(layer "In4.Cu")
		(net "JTAG_DBP_TCK_PCH")
	)
	(segment
		(start 212.716364 -27.723592)
		(end 212.716364 -26.096722)
		(width 0.127)
		(layer "In4.Cu")
		(net "JTAG_DBP_TCK_PCH")
	)
	(segment
		(start 148.1836 -23.508208)
		(end 141.528292 -30.163516)
		(width 0.127)
		(layer "In4.Cu")
		(net "JTAG_DBP_TCK_PCH")
	)
	(segment
		(start 213.90864 -28.501848)
		(end 213.445598 -28.038806)
		(width 0.127)
		(layer "In4.Cu")
		(net "JTAG_DBP_TCK_PCH")
	)
	(segment
		(start 162.1028 -17.695164)
		(end 162.1028 -18.418048)
		(width 0.127)
		(layer "In4.Cu")
		(net "JTAG_DBP_TCK_PCH")
	)
	(segment
		(start 111.43234 -45.5295)
		(end 111.43234 -52.031138)
		(width 0.127)
		(layer "In4.Cu")
		(net "JTAG_DBP_TCK_PCH")
	)
	(segment
		(start 141.528292 -30.163516)
		(end 139.374372 -30.163516)
		(width 0.127)
		(layer "In4.Cu")
		(net "JTAG_DBP_TCK_PCH")
	)
	(segment
		(start 387.312662 -59.785504)
		(end 387.246622 -59.719464)
		(width 0.12954)
		(layer "F.Cu")
		(net "JTAG_DBP_PRESENT_R_N")
	)
	(segment
		(start 387.776974 -60.249816)
		(end 387.312662 -59.785504)
		(width 0.12954)
		(layer "F.Cu")
		(net "JTAG_DBP_PRESENT_R_N")
	)
	(segment
		(start 387.246622 -59.719464)
		(end 386.116322 -59.719464)
		(width 0.12954)
		(layer "F.Cu")
		(net "JTAG_DBP_PRESENT_R_N")
	)
	(segment
		(start 392.034776 -60.249816)
		(end 387.776974 -60.249816)
		(width 0.12954)
		(layer "F.Cu")
		(net "JTAG_DBP_PRESENT_R_N")
	)
	(segment
		(start 386.116322 -58.703464)
		(end 386.116322 -59.719464)
		(width 0.12954)
		(layer "F.Cu")
		(net "JTAG_DBP_PRESENT_R_N")
	)
	(via
		(at 387.312662 -59.785504)
		(size 0.762)
		(drill 0.381)
		(layers "F.Cu" "B.Cu")
		(net "JTAG_DBP_PRESENT_R_N")
	)
	(segment
		(start 369.80368 -94.661228)
		(end 369.259358 -94.116906)
		(width 0.12954)
		(layer "F.Cu")
		(net "JTAG_DBP_PREQ_R_N")
	)
	(segment
		(start 369.80368 -94.981014)
		(end 369.80368 -94.661228)
		(width 0.12954)
		(layer "F.Cu")
		(net "JTAG_DBP_PREQ_R_N")
	)
	(segment
		(start 370.372386 -95.54972)
		(end 369.80368 -94.981014)
		(width 0.12954)
		(layer "F.Cu")
		(net "JTAG_DBP_PREQ_R_N")
	)
	(segment
		(start 369.259358 -94.116906)
		(end 369.259358 -93.363034)
		(width 0.12954)
		(layer "F.Cu")
		(net "JTAG_DBP_PREQ_R_N")
	)
	(segment
		(start 370.372386 -96.264984)
		(end 370.372386 -95.54972)
		(width 0.12954)
		(layer "F.Cu")
		(net "JTAG_DBP_PREQ_R_N")
	)
	(via
		(at 369.80368 -94.981014)
		(size 0.508)
		(drill 0.254)
		(layers "F.Cu" "B.Cu")
		(net "JTAG_DBP_PREQ_R_N")
	)
	(segment
		(start 403.249384 -62.249812)
		(end 399.68424 -62.249812)
		(width 0.12954)
		(layer "F.Cu")
		(net "JTAG_DBP_PREQ_N_R")
	)
	(segment
		(start 399.68424 -62.249812)
		(end 397.765016 -62.249812)
		(width 0.12954)
		(layer "F.Cu")
		(net "JTAG_DBP_PREQ_N_R")
	)
	(segment
		(start 403.551136 -61.94806)
		(end 403.249384 -62.249812)
		(width 0.12954)
		(layer "F.Cu")
		(net "JTAG_DBP_PREQ_N_R")
	)
	(via
		(at 399.68424 -62.249812)
		(size 0.508)
		(drill 0.254)
		(layers "F.Cu" "B.Cu")
		(net "JTAG_DBP_PREQ_N_R")
	)
	(segment
		(start 373.80672 -66.007488)
		(end 373.80672 -66.854832)
		(width 0.12954)
		(layer "F.Cu")
		(net "JTAG_DBP_PREQ_N")
	)
	(segment
		(start 372.163086 -66.421254)
		(end 370.55552 -66.421254)
		(width 0.12954)
		(layer "F.Cu")
		(net "JTAG_DBP_PREQ_N")
	)
	(segment
		(start 406.326848 -61.94806)
		(end 404.351236 -61.94806)
		(width 0.12954)
		(layer "F.Cu")
		(net "JTAG_DBP_PREQ_N")
	)
	(segment
		(start 407.47696 -60.513468)
		(end 407.47696 -60.797948)
		(width 0.12954)
		(layer "F.Cu")
		(net "JTAG_DBP_PREQ_N")
	)
	(segment
		(start 373.80672 -66.854832)
		(end 373.76354 -66.898012)
		(width 0.12954)
		(layer "F.Cu")
		(net "JTAG_DBP_PREQ_N")
	)
	(segment
		(start 373.76354 -66.898012)
		(end 372.639844 -66.898012)
		(width 0.12954)
		(layer "F.Cu")
		(net "JTAG_DBP_PREQ_N")
	)
	(segment
		(start 372.639844 -66.898012)
		(end 372.163086 -66.421254)
		(width 0.12954)
		(layer "F.Cu")
		(net "JTAG_DBP_PREQ_N")
	)
	(segment
		(start 369.259358 -87.86749)
		(end 369.259358 -92.562934)
		(width 0.12954)
		(layer "F.Cu")
		(net "JTAG_DBP_PREQ_N")
	)
	(segment
		(start 370.01958 -87.107268)
		(end 369.259358 -87.86749)
		(width 0.12954)
		(layer "F.Cu")
		(net "JTAG_DBP_PREQ_N")
	)
	(segment
		(start 407.47696 -60.797948)
		(end 406.326848 -61.94806)
		(width 0.12954)
		(layer "F.Cu")
		(net "JTAG_DBP_PREQ_N")
	)
	(segment
		(start 373.80926 -66.004948)
		(end 373.80672 -66.007488)
		(width 0.12954)
		(layer "F.Cu")
		(net "JTAG_DBP_PREQ_N")
	)
	(via
		(at 373.80926 -66.004948)
		(size 0.508)
		(drill 0.254)
		(layers "F.Cu" "B.Cu")
		(net "JTAG_DBP_PREQ_N")
	)
	(via
		(at 370.01958 -87.107268)
		(size 0.508)
		(drill 0.254)
		(layers "F.Cu" "B.Cu")
		(net "JTAG_DBP_PREQ_N")
	)
	(via
		(at 407.47696 -60.513468)
		(size 0.508)
		(drill 0.254)
		(layers "F.Cu" "B.Cu")
		(net "JTAG_DBP_PREQ_N")
	)
	(segment
		(start 369.12804 -73.637648)
		(end 373.80672 -68.958968)
		(width 0.127)
		(layer "In2.Cu")
		(net "JTAG_DBP_PREQ_N")
	)
	(segment
		(start 369.12804 -86.215728)
		(end 369.12804 -73.637648)
		(width 0.127)
		(layer "In2.Cu")
		(net "JTAG_DBP_PREQ_N")
	)
	(segment
		(start 370.01958 -87.107268)
		(end 369.12804 -86.215728)
		(width 0.127)
		(layer "In2.Cu")
		(net "JTAG_DBP_PREQ_N")
	)
	(segment
		(start 373.80672 -68.958968)
		(end 373.80672 -66.007488)
		(width 0.127)
		(layer "In2.Cu")
		(net "JTAG_DBP_PREQ_N")
	)
	(segment
		(start 373.80672 -66.007488)
		(end 373.80926 -66.004948)
		(width 0.127)
		(layer "In2.Cu")
		(net "JTAG_DBP_PREQ_N")
	)
	(segment
		(start 406.96388 -61.026548)
		(end 403.86762 -61.026548)
		(width 0.127)
		(layer "In6.Cu")
		(net "JTAG_DBP_PREQ_N")
	)
	(segment
		(start 378.38888 -65.598548)
		(end 374.21566 -65.598548)
		(width 0.127)
		(layer "In6.Cu")
		(net "JTAG_DBP_PREQ_N")
	)
	(segment
		(start 403.86762 -61.026548)
		(end 399.52422 -65.369948)
		(width 0.127)
		(layer "In6.Cu")
		(net "JTAG_DBP_PREQ_N")
	)
	(segment
		(start 397.26108 -65.369948)
		(end 394.15212 -68.478908)
		(width 0.127)
		(layer "In6.Cu")
		(net "JTAG_DBP_PREQ_N")
	)
	(segment
		(start 381.26924 -68.478908)
		(end 378.38888 -65.598548)
		(width 0.127)
		(layer "In6.Cu")
		(net "JTAG_DBP_PREQ_N")
	)
	(segment
		(start 407.47696 -60.513468)
		(end 406.96388 -61.026548)
		(width 0.127)
		(layer "In6.Cu")
		(net "JTAG_DBP_PREQ_N")
	)
	(segment
		(start 394.15212 -68.478908)
		(end 381.26924 -68.478908)
		(width 0.127)
		(layer "In6.Cu")
		(net "JTAG_DBP_PREQ_N")
	)
	(segment
		(start 374.21566 -65.598548)
		(end 373.80926 -66.004948)
		(width 0.127)
		(layer "In6.Cu")
		(net "JTAG_DBP_PREQ_N")
	)
	(segment
		(start 399.52422 -65.369948)
		(end 397.26108 -65.369948)
		(width 0.127)
		(layer "In6.Cu")
		(net "JTAG_DBP_PREQ_N")
	)
	(segment
		(start 378.686314 -103.580946)
		(end 378.686314 -104.475788)
		(width 0.12954)
		(layer "F.Cu")
		(net "JTAG_DBP_PRDY_R_N")
	)
	(segment
		(start 378.303536 -104.858566)
		(end 378.303536 -105.083102)
		(width 0.12954)
		(layer "F.Cu")
		(net "JTAG_DBP_PRDY_R_N")
	)
	(segment
		(start 378.318522 -103.213154)
		(end 378.557536 -103.452168)
		(width 0.12954)
		(layer "F.Cu")
		(net "JTAG_DBP_PRDY_R_N")
	)
	(segment
		(start 378.686314 -104.475788)
		(end 378.303536 -104.858566)
		(width 0.12954)
		(layer "F.Cu")
		(net "JTAG_DBP_PRDY_R_N")
	)
	(segment
		(start 378.557536 -103.452168)
		(end 378.686314 -103.580946)
		(width 0.12954)
		(layer "F.Cu")
		(net "JTAG_DBP_PRDY_R_N")
	)
	(segment
		(start 378.318522 -102.054152)
		(end 378.318522 -103.213154)
		(width 0.12954)
		(layer "F.Cu")
		(net "JTAG_DBP_PRDY_R_N")
	)
	(via
		(at 378.557536 -103.452168)
		(size 0.508)
		(drill 0.254)
		(layers "F.Cu" "B.Cu")
		(net "JTAG_DBP_PRDY_R_N")
	)
	(segment
		(start 389.987028 -61.74994)
		(end 389.5471 -62.189868)
		(width 0.12954)
		(layer "F.Cu")
		(net "JTAG_DBP_PRDY_R1_N")
	)
	(segment
		(start 386.18033 -61.74994)
		(end 386.116322 -61.813948)
		(width 0.12954)
		(layer "F.Cu")
		(net "JTAG_DBP_PRDY_R1_N")
	)
	(segment
		(start 389.5471 -62.189868)
		(end 387.30936 -62.189868)
		(width 0.12954)
		(layer "F.Cu")
		(net "JTAG_DBP_PRDY_R1_N")
	)
	(segment
		(start 392.034776 -61.74994)
		(end 389.987028 -61.74994)
		(width 0.12954)
		(layer "F.Cu")
		(net "JTAG_DBP_PRDY_R1_N")
	)
	(segment
		(start 386.869432 -61.74994)
		(end 386.18033 -61.74994)
		(width 0.12954)
		(layer "F.Cu")
		(net "JTAG_DBP_PRDY_R1_N")
	)
	(segment
		(start 387.30936 -62.189868)
		(end 386.869432 -61.74994)
		(width 0.12954)
		(layer "F.Cu")
		(net "JTAG_DBP_PRDY_R1_N")
	)
	(via
		(at 387.30936 -62.189868)
		(size 0.762)
		(drill 0.381)
		(layers "F.Cu" "B.Cu")
		(net "JTAG_DBP_PRDY_R1_N")
	)
	(segment
		(start 378.303536 -105.883202)
		(end 377.66752 -105.883202)
		(width 0.12954)
		(layer "F.Cu")
		(net "JTAG_DBP_PRDY_N")
	)
	(segment
		(start 385.316222 -61.813948)
		(end 383.29616 -61.813948)
		(width 0.12954)
		(layer "F.Cu")
		(net "JTAG_DBP_PRDY_N")
	)
	(segment
		(start 373.76354 -64.866012)
		(end 371.750844 -64.866012)
		(width 0.12954)
		(layer "F.Cu")
		(net "JTAG_DBP_PRDY_N")
	)
	(segment
		(start 373.76354 -64.866012)
		(end 373.76354 -64.231012)
		(width 0.12954)
		(layer "F.Cu")
		(net "JTAG_DBP_PRDY_N")
	)
	(segment
		(start 371.750844 -64.866012)
		(end 371.356128 -64.471296)
		(width 0.12954)
		(layer "F.Cu")
		(net "JTAG_DBP_PRDY_N")
	)
	(segment
		(start 371.356128 -64.471296)
		(end 370.55552 -64.471296)
		(width 0.12954)
		(layer "F.Cu")
		(net "JTAG_DBP_PRDY_N")
	)
	(via
		(at 373.76354 -64.231012)
		(size 0.508)
		(drill 0.254)
		(layers "F.Cu" "B.Cu")
		(net "JTAG_DBP_PRDY_N")
	)
	(via
		(at 377.66752 -105.883202)
		(size 0.508)
		(drill 0.254)
		(layers "F.Cu" "B.Cu")
		(net "JTAG_DBP_PRDY_N")
	)
	(via
		(at 383.29616 -61.813948)
		(size 0.508)
		(drill 0.254)
		(layers "F.Cu" "B.Cu")
		(net "JTAG_DBP_PRDY_N")
	)
	(segment
		(start 378.59716 -65.512188)
		(end 375.044716 -65.512188)
		(width 0.12954)
		(layer "B.Cu")
		(net "JTAG_DBP_PRDY_N")
	)
	(segment
		(start 383.29616 -61.813948)
		(end 382.2954 -61.813948)
		(width 0.12954)
		(layer "B.Cu")
		(net "JTAG_DBP_PRDY_N")
	)
	(segment
		(start 375.044716 -65.512188)
		(end 373.76354 -64.231012)
		(width 0.12954)
		(layer "B.Cu")
		(net "JTAG_DBP_PRDY_N")
	)
	(segment
		(start 382.2954 -61.813948)
		(end 378.59716 -65.512188)
		(width 0.12954)
		(layer "B.Cu")
		(net "JTAG_DBP_PRDY_N")
	)
	(segment
		(start 374.57126 -94.735142)
		(end 374.57126 -90.902028)
		(width 0.127)
		(layer "In2.Cu")
		(net "JTAG_DBP_PRDY_N")
	)
	(segment
		(start 374.57126 -90.902028)
		(end 371.99824 -88.329008)
		(width 0.127)
		(layer "In2.Cu")
		(net "JTAG_DBP_PRDY_N")
	)
	(segment
		(start 371.99824 -88.329008)
		(end 371.99824 -71.496428)
		(width 0.127)
		(layer "In2.Cu")
		(net "JTAG_DBP_PRDY_N")
	)
	(segment
		(start 377.66752 -105.883202)
		(end 377.086114 -105.883202)
		(width 0.127)
		(layer "In2.Cu")
		(net "JTAG_DBP_PRDY_N")
	)
	(segment
		(start 374.2436 -95.062802)
		(end 374.57126 -94.735142)
		(width 0.127)
		(layer "In2.Cu")
		(net "JTAG_DBP_PRDY_N")
	)
	(segment
		(start 374.2436 -103.040688)
		(end 374.2436 -95.062802)
		(width 0.127)
		(layer "In2.Cu")
		(net "JTAG_DBP_PRDY_N")
	)
	(segment
		(start 377.086114 -105.883202)
		(end 374.2436 -103.040688)
		(width 0.127)
		(layer "In2.Cu")
		(net "JTAG_DBP_PRDY_N")
	)
	(segment
		(start 374.97512 -68.519548)
		(end 374.97512 -65.442592)
		(width 0.127)
		(layer "In2.Cu")
		(net "JTAG_DBP_PRDY_N")
	)
	(segment
		(start 371.99824 -71.496428)
		(end 374.97512 -68.519548)
		(width 0.127)
		(layer "In2.Cu")
		(net "JTAG_DBP_PRDY_N")
	)
	(segment
		(start 374.97512 -65.442592)
		(end 373.76354 -64.231012)
		(width 0.127)
		(layer "In2.Cu")
		(net "JTAG_DBP_PRDY_N")
	)
	(segment
		(start 395.7066 -55.507128)
		(end 396.463774 -54.749954)
		(width 0.12954)
		(layer "F.Cu")
		(net "JTAG_DBP_POWER_BTN_N")
	)
	(segment
		(start 396.463774 -54.749954)
		(end 397.765016 -54.749954)
		(width 0.12954)
		(layer "F.Cu")
		(net "JTAG_DBP_POWER_BTN_N")
	)
	(segment
		(start 395.7066 -55.971948)
		(end 395.7066 -55.507128)
		(width 0.12954)
		(layer "F.Cu")
		(net "JTAG_DBP_POWER_BTN_N")
	)
	(via
		(at 395.7066 -55.971948)
		(size 0.508)
		(drill 0.254)
		(layers "F.Cu" "B.Cu")
		(net "JTAG_DBP_POWER_BTN_N")
	)
	(segment
		(start 403.611842 -53.732684)
		(end 403.606762 -53.727604)
		(width 0.12954)
		(layer "B.Cu")
		(net "JTAG_DBP_POWER_BTN_N")
	)
	(segment
		(start 401.362418 -55.971948)
		(end 403.606762 -53.727604)
		(width 0.12954)
		(layer "B.Cu")
		(net "JTAG_DBP_POWER_BTN_N")
	)
	(segment
		(start 403.611842 -54.754272)
		(end 403.611842 -53.732684)
		(width 0.12954)
		(layer "B.Cu")
		(net "JTAG_DBP_POWER_BTN_N")
	)
	(segment
		(start 395.7066 -55.971948)
		(end 401.362418 -55.971948)
		(width 0.12954)
		(layer "B.Cu")
		(net "JTAG_DBP_POWER_BTN_N")
	)
	(segment
		(start 365.965994 -40.262302)
		(end 365.965994 -33.922462)
		(width 0.12954)
		(layer "F.Cu")
		(net "JTAG_DBP_PMODE")
	)
	(segment
		(start 371.26672 -42.144188)
		(end 370.73332 -41.610788)
		(width 0.12954)
		(layer "F.Cu")
		(net "JTAG_DBP_PMODE")
	)
	(segment
		(start 383.74574 -63.541148)
		(end 384.30454 -64.099948)
		(width 0.12954)
		(layer "F.Cu")
		(net "JTAG_DBP_PMODE")
	)
	(segment
		(start 345.839796 -38.108382)
		(end 345.895676 -38.191694)
		(width 0.0889)
		(layer "F.Cu")
		(net "JTAG_DBP_PMODE")
	)
	(segment
		(start 346.281756 -36.31819)
		(end 346.103194 -36.31819)
		(width 0.0889)
		(layer "F.Cu")
		(net "JTAG_DBP_PMODE")
	)
	(segment
		(start 389.673846 -63.210948)
		(end 386.328666 -63.210948)
		(width 0.12954)
		(layer "F.Cu")
		(net "JTAG_DBP_PMODE")
	)
	(segment
		(start 369.8367 -41.702228)
		(end 367.40592 -41.702228)
		(width 0.12954)
		(layer "F.Cu")
		(net "JTAG_DBP_PMODE")
	)
	(segment
		(start 371.26672 -49.045114)
		(end 371.26672 -42.144188)
		(width 0.12954)
		(layer "F.Cu")
		(net "JTAG_DBP_PMODE")
	)
	(segment
		(start 370.169694 -50.14214)
		(end 371.26672 -49.045114)
		(width 0.12954)
		(layer "F.Cu")
		(net "JTAG_DBP_PMODE")
	)
	(segment
		(start 386.328666 -63.210948)
		(end 386.116322 -63.423292)
		(width 0.12954)
		(layer "F.Cu")
		(net "JTAG_DBP_PMODE")
	)
	(segment
		(start 351.026476 -24.425148)
		(end 350.238822 -25.212802)
		(width 0.12954)
		(layer "F.Cu")
		(net "JTAG_DBP_PMODE")
	)
	(segment
		(start 349.396812 -28.161996)
		(end 349.396812 -30.455108)
		(width 0.12954)
		(layer "F.Cu")
		(net "JTAG_DBP_PMODE")
	)
	(segment
		(start 345.895676 -38.191694)
		(end 345.904058 -38.212014)
		(width 0.0889)
		(layer "F.Cu")
		(net "JTAG_DBP_PMODE")
	)
	(segment
		(start 369.92814 -41.610788)
		(end 369.8367 -41.702228)
		(width 0.12954)
		(layer "F.Cu")
		(net "JTAG_DBP_PMODE")
	)
	(segment
		(start 385.439666 -64.099948)
		(end 386.116322 -63.423292)
		(width 0.12954)
		(layer "F.Cu")
		(net "JTAG_DBP_PMODE")
	)
	(segment
		(start 383.74574 -63.434468)
		(end 383.74574 -63.541148)
		(width 0.12954)
		(layer "F.Cu")
		(net "JTAG_DBP_PMODE")
	)
	(segment
		(start 390.134856 -62.749938)
		(end 389.673846 -63.210948)
		(width 0.12954)
		(layer "F.Cu")
		(net "JTAG_DBP_PMODE")
	)
	(segment
		(start 345.539822 -36.881562)
		(end 345.539822 -37.76218)
		(width 0.0889)
		(layer "F.Cu")
		(net "JTAG_DBP_PMODE")
	)
	(segment
		(start 348.52356 -31.32836)
		(end 348.52356 -34.885122)
		(width 0.12954)
		(layer "F.Cu")
		(net "JTAG_DBP_PMODE")
	)
	(segment
		(start 345.539822 -37.76218)
		(end 345.629484 -37.851842)
		(width 0.0889)
		(layer "F.Cu")
		(net "JTAG_DBP_PMODE")
	)
	(segment
		(start 367.40592 -41.702228)
		(end 365.965994 -40.262302)
		(width 0.12954)
		(layer "F.Cu")
		(net "JTAG_DBP_PMODE")
	)
	(segment
		(start 370.169694 -52.319428)
		(end 370.169694 -50.14214)
		(width 0.12954)
		(layer "F.Cu")
		(net "JTAG_DBP_PMODE")
	)
	(segment
		(start 349.396812 -30.455108)
		(end 348.52356 -31.32836)
		(width 0.12954)
		(layer "F.Cu")
		(net "JTAG_DBP_PMODE")
	)
	(segment
		(start 348.52356 -34.885122)
		(end 347.090492 -36.31819)
		(width 0.12954)
		(layer "F.Cu")
		(net "JTAG_DBP_PMODE")
	)
	(segment
		(start 345.904058 -38.212014)
		(end 345.904058 -38.465252)
		(width 0.0889)
		(layer "F.Cu")
		(net "JTAG_DBP_PMODE")
	)
	(segment
		(start 346.103194 -36.31819)
		(end 345.539822 -36.881562)
		(width 0.0889)
		(layer "F.Cu")
		(net "JTAG_DBP_PMODE")
	)
	(segment
		(start 350.238822 -27.319986)
		(end 349.396812 -28.161996)
		(width 0.12954)
		(layer "F.Cu")
		(net "JTAG_DBP_PMODE")
	)
	(segment
		(start 370.73332 -41.610788)
		(end 369.92814 -41.610788)
		(width 0.12954)
		(layer "F.Cu")
		(net "JTAG_DBP_PMODE")
	)
	(segment
		(start 347.090492 -36.31819)
		(end 346.281756 -36.31819)
		(width 0.12954)
		(layer "F.Cu")
		(net "JTAG_DBP_PMODE")
	)
	(segment
		(start 345.629484 -37.851842)
		(end 345.839796 -38.108382)
		(width 0.0889)
		(layer "F.Cu")
		(net "JTAG_DBP_PMODE")
	)
	(segment
		(start 356.46868 -24.425148)
		(end 351.026476 -24.425148)
		(width 0.12954)
		(layer "F.Cu")
		(net "JTAG_DBP_PMODE")
	)
	(segment
		(start 392.034776 -62.749938)
		(end 390.134856 -62.749938)
		(width 0.12954)
		(layer "F.Cu")
		(net "JTAG_DBP_PMODE")
	)
	(segment
		(start 384.30454 -64.099948)
		(end 385.439666 -64.099948)
		(width 0.12954)
		(layer "F.Cu")
		(net "JTAG_DBP_PMODE")
	)
	(segment
		(start 350.238822 -25.212802)
		(end 350.238822 -27.319986)
		(width 0.12954)
		(layer "F.Cu")
		(net "JTAG_DBP_PMODE")
	)
	(segment
		(start 365.965994 -33.922462)
		(end 356.46868 -24.425148)
		(width 0.12954)
		(layer "F.Cu")
		(net "JTAG_DBP_PMODE")
	)
	(via
		(at 370.169694 -52.319428)
		(size 0.508)
		(drill 0.254)
		(layers "F.Cu" "B.Cu")
		(net "JTAG_DBP_PMODE")
	)
	(via
		(at 383.74574 -63.434468)
		(size 0.508)
		(drill 0.254)
		(layers "F.Cu" "B.Cu")
		(net "JTAG_DBP_PMODE")
	)
	(segment
		(start 370.93652 -51.399948)
		(end 374.49506 -51.399948)
		(width 0.127)
		(layer "In2.Cu")
		(net "JTAG_DBP_PMODE")
	)
	(segment
		(start 375.158 -52.062888)
		(end 375.158 -54.846728)
		(width 0.127)
		(layer "In2.Cu")
		(net "JTAG_DBP_PMODE")
	)
	(segment
		(start 375.158 -54.846728)
		(end 383.74574 -63.434468)
		(width 0.127)
		(layer "In2.Cu")
		(net "JTAG_DBP_PMODE")
	)
	(segment
		(start 374.49506 -51.399948)
		(end 375.158 -52.062888)
		(width 0.127)
		(layer "In2.Cu")
		(net "JTAG_DBP_PMODE")
	)
	(segment
		(start 370.169694 -52.166774)
		(end 370.93652 -51.399948)
		(width 0.127)
		(layer "In2.Cu")
		(net "JTAG_DBP_PMODE")
	)
	(segment
		(start 370.169694 -52.319428)
		(end 370.169694 -52.166774)
		(width 0.127)
		(layer "In2.Cu")
		(net "JTAG_DBP_PMODE")
	)
	(segment
		(start 392.034776 -60.749942)
		(end 388.487666 -60.749942)
		(width 0.12954)
		(layer "F.Cu")
		(net "JTAG_DBP_PCH_DEBUG_CONSENT_N")
	)
	(segment
		(start 388.33044 -60.907168)
		(end 388.173214 -60.749942)
		(width 0.12954)
		(layer "F.Cu")
		(net "JTAG_DBP_PCH_DEBUG_CONSENT_N")
	)
	(segment
		(start 386.1308 -60.749942)
		(end 386.116322 -60.735464)
		(width 0.12954)
		(layer "F.Cu")
		(net "JTAG_DBP_PCH_DEBUG_CONSENT_N")
	)
	(segment
		(start 388.487666 -60.749942)
		(end 388.33044 -60.907168)
		(width 0.12954)
		(layer "F.Cu")
		(net "JTAG_DBP_PCH_DEBUG_CONSENT_N")
	)
	(segment
		(start 388.173214 -60.749942)
		(end 386.1308 -60.749942)
		(width 0.12954)
		(layer "F.Cu")
		(net "JTAG_DBP_PCH_DEBUG_CONSENT_N")
	)
	(via
		(at 388.33044 -60.907168)
		(size 0.762)
		(drill 0.381)
		(layers "F.Cu" "B.Cu")
		(net "JTAG_DBP_PCH_DEBUG_CONSENT_N")
	)
	(segment
		(start 373.772684 -94.187518)
		(end 372.97233 -94.987872)
		(width 0.12954)
		(layer "F.Cu")
		(net "JTAG_DBP_FB_TMS")
	)
	(segment
		(start 373.577358 -93.684344)
		(end 374.080532 -94.187518)
		(width 0.12954)
		(layer "F.Cu")
		(net "JTAG_DBP_FB_TMS")
	)
	(segment
		(start 373.577358 -93.363034)
		(end 373.577358 -93.684344)
		(width 0.12954)
		(layer "F.Cu")
		(net "JTAG_DBP_FB_TMS")
	)
	(segment
		(start 372.97233 -94.987872)
		(end 372.97233 -96.264984)
		(width 0.12954)
		(layer "F.Cu")
		(net "JTAG_DBP_FB_TMS")
	)
	(segment
		(start 374.080532 -94.187518)
		(end 373.772684 -94.187518)
		(width 0.12954)
		(layer "F.Cu")
		(net "JTAG_DBP_FB_TMS")
	)
	(via
		(at 374.080532 -94.187518)
		(size 0.508)
		(drill 0.254)
		(layers "F.Cu" "B.Cu")
		(net "JTAG_DBP_FB_TMS")
	)
	(segment
		(start 376.368564 -103.184452)
		(end 376.368564 -102.054152)
		(width 0.12954)
		(layer "F.Cu")
		(net "JTAG_DBP_FB_TDO")
	)
	(segment
		(start 375.255536 -105.083102)
		(end 375.255536 -104.29748)
		(width 0.12954)
		(layer "F.Cu")
		(net "JTAG_DBP_FB_TDO")
	)
	(segment
		(start 375.255536 -104.29748)
		(end 376.368564 -103.184452)
		(width 0.12954)
		(layer "F.Cu")
		(net "JTAG_DBP_FB_TDO")
	)
	(via
		(at 376.368564 -103.184452)
		(size 0.508)
		(drill 0.254)
		(layers "F.Cu" "B.Cu")
		(net "JTAG_DBP_FB_TDO")
	)
	(segment
		(start 372.322344 -94.695518)
		(end 372.322344 -96.264984)
		(width 0.12954)
		(layer "F.Cu")
		(net "JTAG_DBP_FB_TDI")
	)
	(segment
		(start 372.561358 -93.363034)
		(end 372.561358 -93.98762)
		(width 0.12954)
		(layer "F.Cu")
		(net "JTAG_DBP_FB_TDI")
	)
	(segment
		(start 372.7958 -94.222062)
		(end 372.322344 -94.695518)
		(width 0.12954)
		(layer "F.Cu")
		(net "JTAG_DBP_FB_TDI")
	)
	(segment
		(start 372.561358 -93.98762)
		(end 372.7958 -94.222062)
		(width 0.12954)
		(layer "F.Cu")
		(net "JTAG_DBP_FB_TDI")
	)
	(via
		(at 372.7958 -94.222062)
		(size 0.508)
		(drill 0.254)
		(layers "F.Cu" "B.Cu")
		(net "JTAG_DBP_FB_TDI")
	)
	(segment
		(start 292.01237 -147.259548)
		(end 296.048938 -143.22298)
		(width 0.12954)
		(layer "F.Cu")
		(net "JTAG_DBP_CPU_QS_GTL_TMS")
	)
	(segment
		(start 351.98558 -129.062988)
		(end 353.74199 -127.306578)
		(width 0.12954)
		(layer "F.Cu")
		(net "JTAG_DBP_CPU_QS_GTL_TMS")
	)
	(segment
		(start 362.797344 -59.178698)
		(end 362.802424 -59.183778)
		(width 0.12954)
		(layer "F.Cu")
		(net "JTAG_DBP_CPU_QS_GTL_TMS")
	)
	(segment
		(start 362.802424 -59.183778)
		(end 364.841282 -59.183778)
		(width 0.12954)
		(layer "F.Cu")
		(net "JTAG_DBP_CPU_QS_GTL_TMS")
	)
	(segment
		(start 353.74199 -127.306578)
		(end 353.74199 -126.743968)
		(width 0.12954)
		(layer "F.Cu")
		(net "JTAG_DBP_CPU_QS_GTL_TMS")
	)
	(segment
		(start 275.424646 -147.259548)
		(end 292.01237 -147.259548)
		(width 0.12954)
		(layer "F.Cu")
		(net "JTAG_DBP_CPU_QS_GTL_TMS")
	)
	(segment
		(start 266.01674 -151.453088)
		(end 266.75588 -150.713948)
		(width 0.12954)
		(layer "F.Cu")
		(net "JTAG_DBP_CPU_QS_GTL_TMS")
	)
	(segment
		(start 296.083228 -143.22298)
		(end 310.24322 -129.062988)
		(width 0.12954)
		(layer "F.Cu")
		(net "JTAG_DBP_CPU_QS_GTL_TMS")
	)
	(segment
		(start 296.048938 -143.22298)
		(end 296.083228 -143.22298)
		(width 0.12954)
		(layer "F.Cu")
		(net "JTAG_DBP_CPU_QS_GTL_TMS")
	)
	(segment
		(start 266.75588 -150.713948)
		(end 270.254984 -150.713948)
		(width 0.12954)
		(layer "F.Cu")
		(net "JTAG_DBP_CPU_QS_GTL_TMS")
	)
	(segment
		(start 362.797344 -59.121548)
		(end 362.797344 -59.178698)
		(width 0.12954)
		(layer "F.Cu")
		(net "JTAG_DBP_CPU_QS_GTL_TMS")
	)
	(segment
		(start 310.24322 -129.062988)
		(end 351.98558 -129.062988)
		(width 0.12954)
		(layer "F.Cu")
		(net "JTAG_DBP_CPU_QS_GTL_TMS")
	)
	(segment
		(start 265.62304 -151.453088)
		(end 266.01674 -151.453088)
		(width 0.12954)
		(layer "F.Cu")
		(net "JTAG_DBP_CPU_QS_GTL_TMS")
	)
	(segment
		(start 270.254984 -150.713948)
		(end 275.424646 -147.259548)
		(width 0.12954)
		(layer "F.Cu")
		(net "JTAG_DBP_CPU_QS_GTL_TMS")
	)
	(via
		(at 266.25804 -152.723088)
		(size 0.508)
		(drill 0.254)
		(layers "F.Cu" "B.Cu")
		(net "JTAG_DBP_CPU_QS_GTL_TMS")
	)
	(via
		(at 265.62304 -151.453088)
		(size 0.508)
		(drill 0.254)
		(layers "F.Cu" "B.Cu")
		(net "JTAG_DBP_CPU_QS_GTL_TMS")
	)
	(via
		(at 362.797344 -59.121548)
		(size 0.508)
		(drill 0.254)
		(layers "F.Cu" "B.Cu")
		(net "JTAG_DBP_CPU_QS_GTL_TMS")
	)
	(via
		(at 353.74199 -126.743968)
		(size 0.508)
		(drill 0.254)
		(layers "F.Cu" "B.Cu")
		(net "JTAG_DBP_CPU_QS_GTL_TMS")
	)
	(via
		(at 185.24093 -148.872702)
		(size 0.508)
		(drill 0.254)
		(layers "F.Cu" "B.Cu")
		(net "JTAG_DBP_CPU_QS_GTL_TMS")
	)
	(segment
		(start 309.732426 -168.389808)
		(end 326.03694 -184.694322)
		(width 0.12954)
		(layer "B.Cu")
		(net "JTAG_DBP_CPU_QS_GTL_TMS")
	)
	(segment
		(start 326.66432 -184.120028)
		(end 326.66432 -188.170058)
		(width 0.12954)
		(layer "B.Cu")
		(net "JTAG_DBP_CPU_QS_GTL_TMS")
	)
	(segment
		(start 265.62304 -151.453088)
		(end 265.62304 -152.959308)
		(width 0.12954)
		(layer "B.Cu")
		(net "JTAG_DBP_CPU_QS_GTL_TMS")
	)
	(segment
		(start 265.62304 -152.959308)
		(end 265.84402 -153.180288)
		(width 0.12954)
		(layer "B.Cu")
		(net "JTAG_DBP_CPU_QS_GTL_TMS")
	)
	(segment
		(start 183.349138 -149.96795)
		(end 181.827678 -149.96795)
		(width 0.12954)
		(layer "B.Cu")
		(net "JTAG_DBP_CPU_QS_GTL_TMS")
	)
	(segment
		(start 266.49172 -154.615388)
		(end 266.49172 -156.507688)
		(width 0.12954)
		(layer "B.Cu")
		(net "JTAG_DBP_CPU_QS_GTL_TMS")
	)
	(segment
		(start 326.66432 -188.170058)
		(end 326.338438 -188.49594)
		(width 0.12954)
		(layer "B.Cu")
		(net "JTAG_DBP_CPU_QS_GTL_TMS")
	)
	(segment
		(start 310.1721 -167.627808)
		(end 326.66432 -184.120028)
		(width 0.12954)
		(layer "B.Cu")
		(net "JTAG_DBP_CPU_QS_GTL_TMS")
	)
	(segment
		(start 86.473284 -190.305182)
		(end 86.463378 -190.295276)
		(width 0.12954)
		(layer "B.Cu")
		(net "JTAG_DBP_CPU_QS_GTL_TMS")
	)
	(segment
		(start 277.61184 -167.627808)
		(end 310.1721 -167.627808)
		(width 0.12954)
		(layer "B.Cu")
		(net "JTAG_DBP_CPU_QS_GTL_TMS")
	)
	(segment
		(start 86.463378 -183.035194)
		(end 85.892894 -182.46471)
		(width 0.12954)
		(layer "B.Cu")
		(net "JTAG_DBP_CPU_QS_GTL_TMS")
	)
	(segment
		(start 265.84402 -153.180288)
		(end 265.84402 -156.730954)
		(width 0.12954)
		(layer "B.Cu")
		(net "JTAG_DBP_CPU_QS_GTL_TMS")
	)
	(segment
		(start 181.827678 -149.96795)
		(end 179.38242 -152.413208)
		(width 0.12954)
		(layer "B.Cu")
		(net "JTAG_DBP_CPU_QS_GTL_TMS")
	)
	(segment
		(start 120.311926 -152.25268)
		(end 119.708168 -152.25268)
		(width 0.12954)
		(layer "B.Cu")
		(net "JTAG_DBP_CPU_QS_GTL_TMS")
	)
	(segment
		(start 267.33754 -153.769568)
		(end 266.49172 -154.615388)
		(width 0.12954)
		(layer "B.Cu")
		(net "JTAG_DBP_CPU_QS_GTL_TMS")
	)
	(segment
		(start 267.33754 -152.987248)
		(end 267.33754 -153.769568)
		(width 0.12954)
		(layer "B.Cu")
		(net "JTAG_DBP_CPU_QS_GTL_TMS")
	)
	(segment
		(start 179.38242 -152.413208)
		(end 120.472454 -152.413208)
		(width 0.12954)
		(layer "B.Cu")
		(net "JTAG_DBP_CPU_QS_GTL_TMS")
	)
	(segment
		(start 266.27836 -152.702768)
		(end 267.05306 -152.702768)
		(width 0.12954)
		(layer "B.Cu")
		(net "JTAG_DBP_CPU_QS_GTL_TMS")
	)
	(segment
		(start 109.95152 -153.025094)
		(end 86.463378 -176.513236)
		(width 0.12954)
		(layer "B.Cu")
		(net "JTAG_DBP_CPU_QS_GTL_TMS")
	)
	(segment
		(start 118.935754 -153.025094)
		(end 109.95152 -153.025094)
		(width 0.12954)
		(layer "B.Cu")
		(net "JTAG_DBP_CPU_QS_GTL_TMS")
	)
	(segment
		(start 86.463378 -176.513236)
		(end 86.463378 -181.894226)
		(width 0.12954)
		(layer "B.Cu")
		(net "JTAG_DBP_CPU_QS_GTL_TMS")
	)
	(segment
		(start 266.25804 -152.723088)
		(end 266.27836 -152.702768)
		(width 0.12954)
		(layer "B.Cu")
		(net "JTAG_DBP_CPU_QS_GTL_TMS")
	)
	(segment
		(start 326.03694 -184.694322)
		(end 326.03694 -188.194442)
		(width 0.12954)
		(layer "B.Cu")
		(net "JTAG_DBP_CPU_QS_GTL_TMS")
	)
	(segment
		(start 86.463378 -190.295276)
		(end 86.463378 -183.035194)
		(width 0.12954)
		(layer "B.Cu")
		(net "JTAG_DBP_CPU_QS_GTL_TMS")
	)
	(segment
		(start 184.444386 -148.872702)
		(end 183.349138 -149.96795)
		(width 0.12954)
		(layer "B.Cu")
		(net "JTAG_DBP_CPU_QS_GTL_TMS")
	)
	(segment
		(start 266.49172 -156.507688)
		(end 277.61184 -167.627808)
		(width 0.12954)
		(layer "B.Cu")
		(net "JTAG_DBP_CPU_QS_GTL_TMS")
	)
	(segment
		(start 119.708168 -152.25268)
		(end 118.935754 -153.025094)
		(width 0.12954)
		(layer "B.Cu")
		(net "JTAG_DBP_CPU_QS_GTL_TMS")
	)
	(segment
		(start 185.24093 -148.872702)
		(end 184.444386 -148.872702)
		(width 0.12954)
		(layer "B.Cu")
		(net "JTAG_DBP_CPU_QS_GTL_TMS")
	)
	(segment
		(start 120.472454 -152.413208)
		(end 120.311926 -152.25268)
		(width 0.12954)
		(layer "B.Cu")
		(net "JTAG_DBP_CPU_QS_GTL_TMS")
	)
	(segment
		(start 277.502874 -168.389808)
		(end 309.732426 -168.389808)
		(width 0.12954)
		(layer "B.Cu")
		(net "JTAG_DBP_CPU_QS_GTL_TMS")
	)
	(segment
		(start 86.463378 -181.894226)
		(end 85.892894 -182.46471)
		(width 0.12954)
		(layer "B.Cu")
		(net "JTAG_DBP_CPU_QS_GTL_TMS")
	)
	(segment
		(start 326.03694 -188.194442)
		(end 326.338438 -188.49594)
		(width 0.12954)
		(layer "B.Cu")
		(net "JTAG_DBP_CPU_QS_GTL_TMS")
	)
	(segment
		(start 267.05306 -152.702768)
		(end 267.33754 -152.987248)
		(width 0.12954)
		(layer "B.Cu")
		(net "JTAG_DBP_CPU_QS_GTL_TMS")
	)
	(segment
		(start 265.84402 -156.730954)
		(end 277.502874 -168.389808)
		(width 0.12954)
		(layer "B.Cu")
		(net "JTAG_DBP_CPU_QS_GTL_TMS")
	)
	(segment
		(start 361.48518 -67.067684)
		(end 363.96168 -73.04659)
		(width 0.127)
		(layer "In2.Cu")
		(net "JTAG_DBP_CPU_QS_GTL_TMS")
	)
	(segment
		(start 362.797344 -59.121548)
		(end 362.797344 -60.049664)
		(width 0.127)
		(layer "In2.Cu")
		(net "JTAG_DBP_CPU_QS_GTL_TMS")
	)
	(segment
		(start 362.797344 -60.049664)
		(end 361.48518 -61.361828)
		(width 0.127)
		(layer "In2.Cu")
		(net "JTAG_DBP_CPU_QS_GTL_TMS")
	)
	(segment
		(start 354.346764 -126.139194)
		(end 353.74199 -126.743968)
		(width 0.127)
		(layer "In2.Cu")
		(net "JTAG_DBP_CPU_QS_GTL_TMS")
	)
	(segment
		(start 365.499904 -108.903516)
		(end 354.346764 -126.139194)
		(width 0.127)
		(layer "In2.Cu")
		(net "JTAG_DBP_CPU_QS_GTL_TMS")
	)
	(segment
		(start 361.48518 -61.361828)
		(end 361.48518 -67.067684)
		(width 0.127)
		(layer "In2.Cu")
		(net "JTAG_DBP_CPU_QS_GTL_TMS")
	)
	(segment
		(start 363.96168 -73.04659)
		(end 363.96168 -83.309714)
		(width 0.127)
		(layer "In2.Cu")
		(net "JTAG_DBP_CPU_QS_GTL_TMS")
	)
	(segment
		(start 363.96168 -83.309714)
		(end 365.499904 -84.847938)
		(width 0.127)
		(layer "In2.Cu")
		(net "JTAG_DBP_CPU_QS_GTL_TMS")
	)
	(segment
		(start 365.499904 -84.847938)
		(end 365.499904 -108.903516)
		(width 0.127)
		(layer "In2.Cu")
		(net "JTAG_DBP_CPU_QS_GTL_TMS")
	)
	(segment
		(start 210.70443 -149.909022)
		(end 208.059274 -149.909022)
		(width 0.127)
		(layer "In4.Cu")
		(net "JTAG_DBP_CPU_QS_GTL_TMS")
	)
	(segment
		(start 196.86016 -147.686268)
		(end 190.31966 -147.686268)
		(width 0.127)
		(layer "In4.Cu")
		(net "JTAG_DBP_CPU_QS_GTL_TMS")
	)
	(segment
		(start 228.45268 -149.570948)
		(end 211.042504 -149.570948)
		(width 0.127)
		(layer "In4.Cu")
		(net "JTAG_DBP_CPU_QS_GTL_TMS")
	)
	(segment
		(start 188.494416 -149.511512)
		(end 185.87974 -149.511512)
		(width 0.127)
		(layer "In4.Cu")
		(net "JTAG_DBP_CPU_QS_GTL_TMS")
	)
	(segment
		(start 265.19632 -148.646388)
		(end 229.37724 -148.646388)
		(width 0.127)
		(layer "In4.Cu")
		(net "JTAG_DBP_CPU_QS_GTL_TMS")
	)
	(segment
		(start 190.31966 -147.686268)
		(end 188.494416 -149.511512)
		(width 0.127)
		(layer "In4.Cu")
		(net "JTAG_DBP_CPU_QS_GTL_TMS")
	)
	(segment
		(start 266.25804 -152.723088)
		(end 266.25804 -149.708108)
		(width 0.127)
		(layer "In4.Cu")
		(net "JTAG_DBP_CPU_QS_GTL_TMS")
	)
	(segment
		(start 266.25804 -149.708108)
		(end 265.19632 -148.646388)
		(width 0.127)
		(layer "In4.Cu")
		(net "JTAG_DBP_CPU_QS_GTL_TMS")
	)
	(segment
		(start 211.042504 -149.570948)
		(end 210.70443 -149.909022)
		(width 0.127)
		(layer "In4.Cu")
		(net "JTAG_DBP_CPU_QS_GTL_TMS")
	)
	(segment
		(start 199.50684 -150.332948)
		(end 196.86016 -147.686268)
		(width 0.127)
		(layer "In4.Cu")
		(net "JTAG_DBP_CPU_QS_GTL_TMS")
	)
	(segment
		(start 208.059274 -149.909022)
		(end 207.7212 -149.570948)
		(width 0.127)
		(layer "In4.Cu")
		(net "JTAG_DBP_CPU_QS_GTL_TMS")
	)
	(segment
		(start 205.85176 -150.332948)
		(end 199.50684 -150.332948)
		(width 0.127)
		(layer "In4.Cu")
		(net "JTAG_DBP_CPU_QS_GTL_TMS")
	)
	(segment
		(start 206.61376 -149.570948)
		(end 205.85176 -150.332948)
		(width 0.127)
		(layer "In4.Cu")
		(net "JTAG_DBP_CPU_QS_GTL_TMS")
	)
	(segment
		(start 207.7212 -149.570948)
		(end 206.61376 -149.570948)
		(width 0.127)
		(layer "In4.Cu")
		(net "JTAG_DBP_CPU_QS_GTL_TMS")
	)
	(segment
		(start 185.87974 -149.511512)
		(end 185.24093 -148.872702)
		(width 0.127)
		(layer "In4.Cu")
		(net "JTAG_DBP_CPU_QS_GTL_TMS")
	)
	(segment
		(start 229.37724 -148.646388)
		(end 228.45268 -149.570948)
		(width 0.127)
		(layer "In4.Cu")
		(net "JTAG_DBP_CPU_QS_GTL_TMS")
	)
	(segment
		(start 364.71352 -67.07124)
		(end 363.58322 -67.07124)
		(width 0.12954)
		(layer "F.Cu")
		(net "JTAG_DBP_CPU_HOOK9_MBP3_GTL_N")
	)
	(segment
		(start 388.779766 -51.249834)
		(end 392.034776 -51.249834)
		(width 0.12954)
		(layer "F.Cu")
		(net "JTAG_DBP_CPU_HOOK9_MBP3_GTL_N")
	)
	(segment
		(start 388.29488 -50.764948)
		(end 388.779766 -51.249834)
		(width 0.12954)
		(layer "F.Cu")
		(net "JTAG_DBP_CPU_HOOK9_MBP3_GTL_N")
	)
	(via
		(at 363.58322 -67.07124)
		(size 0.508)
		(drill 0.254)
		(layers "F.Cu" "B.Cu")
		(net "JTAG_DBP_CPU_HOOK9_MBP3_GTL_N")
	)
	(via
		(at 388.29488 -50.764948)
		(size 0.508)
		(drill 0.254)
		(layers "F.Cu" "B.Cu")
		(net "JTAG_DBP_CPU_HOOK9_MBP3_GTL_N")
	)
	(segment
		(start 388.29488 -51.265328)
		(end 388.29488 -50.764948)
		(width 0.12954)
		(layer "B.Cu")
		(net "JTAG_DBP_CPU_HOOK9_MBP3_GTL_N")
	)
	(segment
		(start 365.37138 -65.28308)
		(end 365.37138 -63.618618)
		(width 0.12954)
		(layer "B.Cu")
		(net "JTAG_DBP_CPU_HOOK9_MBP3_GTL_N")
	)
	(segment
		(start 363.58322 -67.07124)
		(end 365.37138 -65.28308)
		(width 0.12954)
		(layer "B.Cu")
		(net "JTAG_DBP_CPU_HOOK9_MBP3_GTL_N")
	)
	(segment
		(start 388.08406 -51.476148)
		(end 388.29488 -51.265328)
		(width 0.12954)
		(layer "B.Cu")
		(net "JTAG_DBP_CPU_HOOK9_MBP3_GTL_N")
	)
	(segment
		(start 365.37138 -63.618618)
		(end 377.51385 -51.476148)
		(width 0.12954)
		(layer "B.Cu")
		(net "JTAG_DBP_CPU_HOOK9_MBP3_GTL_N")
	)
	(segment
		(start 377.51385 -51.476148)
		(end 388.08406 -51.476148)
		(width 0.12954)
		(layer "B.Cu")
		(net "JTAG_DBP_CPU_HOOK9_MBP3_GTL_N")
	)
	(segment
		(start 364.71352 -65.121282)
		(end 363.58322 -65.121282)
		(width 0.12954)
		(layer "F.Cu")
		(net "JTAG_DBP_CPU_HOOK8_MBP2_GTL_N")
	)
	(segment
		(start 392.034776 -50.749962)
		(end 389.81888 -50.749962)
		(width 0.12954)
		(layer "F.Cu")
		(net "JTAG_DBP_CPU_HOOK8_MBP2_GTL_N")
	)
	(via
		(at 363.58322 -65.121282)
		(size 0.508)
		(drill 0.254)
		(layers "F.Cu" "B.Cu")
		(net "JTAG_DBP_CPU_HOOK8_MBP2_GTL_N")
	)
	(via
		(at 389.81888 -50.749962)
		(size 0.508)
		(drill 0.254)
		(layers "F.Cu" "B.Cu")
		(net "JTAG_DBP_CPU_HOOK8_MBP2_GTL_N")
	)
	(segment
		(start 389.29564 -50.117248)
		(end 389.81888 -50.640488)
		(width 0.12954)
		(layer "B.Cu")
		(net "JTAG_DBP_CPU_HOOK8_MBP2_GTL_N")
	)
	(segment
		(start 377.36018 -51.105308)
		(end 386.9055 -51.105308)
		(width 0.12954)
		(layer "B.Cu")
		(net "JTAG_DBP_CPU_HOOK8_MBP2_GTL_N")
	)
	(segment
		(start 387.89356 -50.117248)
		(end 389.29564 -50.117248)
		(width 0.12954)
		(layer "B.Cu")
		(net "JTAG_DBP_CPU_HOOK8_MBP2_GTL_N")
	)
	(segment
		(start 363.58322 -64.882268)
		(end 377.36018 -51.105308)
		(width 0.12954)
		(layer "B.Cu")
		(net "JTAG_DBP_CPU_HOOK8_MBP2_GTL_N")
	)
	(segment
		(start 389.81888 -50.640488)
		(end 389.81888 -50.749962)
		(width 0.12954)
		(layer "B.Cu")
		(net "JTAG_DBP_CPU_HOOK8_MBP2_GTL_N")
	)
	(segment
		(start 363.58322 -65.121282)
		(end 363.58322 -64.882268)
		(width 0.12954)
		(layer "B.Cu")
		(net "JTAG_DBP_CPU_HOOK8_MBP2_GTL_N")
	)
	(segment
		(start 386.9055 -51.105308)
		(end 387.89356 -50.117248)
		(width 0.12954)
		(layer "B.Cu")
		(net "JTAG_DBP_CPU_HOOK8_MBP2_GTL_N")
	)
	(segment
		(start 97.902014 -53.977032)
		(end 96.97593 -53.050948)
		(width 0.12954)
		(layer "F.Cu")
		(net "JTAG_DBP_CPU_GTL_TCK_R1")
	)
	(segment
		(start 98.22688 -53.977032)
		(end 97.902014 -53.977032)
		(width 0.12954)
		(layer "F.Cu")
		(net "JTAG_DBP_CPU_GTL_TCK_R1")
	)
	(segment
		(start 99.92741 -53.977032)
		(end 98.22688 -53.977032)
		(width 0.12954)
		(layer "F.Cu")
		(net "JTAG_DBP_CPU_GTL_TCK_R1")
	)
	(via
		(at 98.22688 -53.977032)
		(size 0.762)
		(drill 0.381)
		(layers "F.Cu" "B.Cu")
		(net "JTAG_DBP_CPU_GTL_TCK_R1")
	)
	(segment
		(start 387.123178 -64.681608)
		(end 386.116322 -65.688464)
		(width 0.12954)
		(layer "F.Cu")
		(net "JTAG_DBP_CPU_GTL_TCK_R")
	)
	(segment
		(start 392.034776 -63.749936)
		(end 390.862312 -63.749936)
		(width 0.12954)
		(layer "F.Cu")
		(net "JTAG_DBP_CPU_GTL_TCK_R")
	)
	(segment
		(start 387.30174 -64.681608)
		(end 387.123178 -64.681608)
		(width 0.12954)
		(layer "F.Cu")
		(net "JTAG_DBP_CPU_GTL_TCK_R")
	)
	(segment
		(start 390.862312 -63.749936)
		(end 389.93064 -64.681608)
		(width 0.12954)
		(layer "F.Cu")
		(net "JTAG_DBP_CPU_GTL_TCK_R")
	)
	(segment
		(start 389.93064 -64.681608)
		(end 387.30174 -64.681608)
		(width 0.12954)
		(layer "F.Cu")
		(net "JTAG_DBP_CPU_GTL_TCK_R")
	)
	(via
		(at 387.30174 -64.681608)
		(size 0.762)
		(drill 0.381)
		(layers "F.Cu" "B.Cu")
		(net "JTAG_DBP_CPU_GTL_TCK_R")
	)
	(segment
		(start 374.93448 -39.284402)
		(end 374.93448 -55.133748)
		(width 0.12954)
		(layer "F.Cu")
		(net "JTAG_DBP_CPU_GTL_TCK")
	)
	(segment
		(start 343.179654 -37.226748)
		(end 343.179654 -37.433504)
		(width 0.0889)
		(layer "F.Cu")
		(net "JTAG_DBP_CPU_GTL_TCK")
	)
	(segment
		(start 382.1811 -64.615568)
		(end 382.651 -65.085468)
		(width 0.12954)
		(layer "F.Cu")
		(net "JTAG_DBP_CPU_GTL_TCK")
	)
	(segment
		(start 343.19083 -37.753036)
		(end 343.032842 -37.990272)
		(width 0.0889)
		(layer "F.Cu")
		(net "JTAG_DBP_CPU_GTL_TCK")
	)
	(segment
		(start 346.464636 -24.761698)
		(end 346.464636 -27.178254)
		(width 0.12954)
		(layer "F.Cu")
		(net "JTAG_DBP_CPU_GTL_TCK")
	)
	(segment
		(start 374.93448 -55.133748)
		(end 381.18288 -61.382148)
		(width 0.12954)
		(layer "F.Cu")
		(net "JTAG_DBP_CPU_GTL_TCK")
	)
	(segment
		(start 343.279222 -36.378388)
		(end 343.279222 -37.12718)
		(width 0.0889)
		(layer "F.Cu")
		(net "JTAG_DBP_CPU_GTL_TCK")
	)
	(segment
		(start 343.179654 -37.433504)
		(end 343.19083 -37.753036)
		(width 0.0889)
		(layer "F.Cu")
		(net "JTAG_DBP_CPU_GTL_TCK")
	)
	(segment
		(start 382.651 -65.085468)
		(end 383.646934 -65.085468)
		(width 0.12954)
		(layer "F.Cu")
		(net "JTAG_DBP_CPU_GTL_TCK")
	)
	(segment
		(start 381.18288 -61.382148)
		(end 381.18288 -63.617348)
		(width 0.12954)
		(layer "F.Cu")
		(net "JTAG_DBP_CPU_GTL_TCK")
	)
	(segment
		(start 343.063068 -38.151562)
		(end 343.230708 -38.345618)
		(width 0.0889)
		(layer "F.Cu")
		(net "JTAG_DBP_CPU_GTL_TCK")
	)
	(segment
		(start 347.29674 -19.799554)
		(end 355.718872 -19.799554)
		(width 0.12954)
		(layer "F.Cu")
		(net "JTAG_DBP_CPU_GTL_TCK")
	)
	(segment
		(start 343.279222 -37.12718)
		(end 343.179654 -37.226748)
		(width 0.0889)
		(layer "F.Cu")
		(net "JTAG_DBP_CPU_GTL_TCK")
	)
	(segment
		(start 343.032842 -38.090602)
		(end 343.063068 -38.151562)
		(width 0.0889)
		(layer "F.Cu")
		(net "JTAG_DBP_CPU_GTL_TCK")
	)
	(segment
		(start 97.33153 -51.895248)
		(end 96.17583 -53.050948)
		(width 0.12954)
		(layer "F.Cu")
		(net "JTAG_DBP_CPU_GTL_TCK")
	)
	(segment
		(start 343.230708 -38.345618)
		(end 343.403174 -38.518084)
		(width 0.0889)
		(layer "F.Cu")
		(net "JTAG_DBP_CPU_GTL_TCK")
	)
	(segment
		(start 343.032842 -37.990272)
		(end 343.032842 -38.090602)
		(width 0.0889)
		(layer "F.Cu")
		(net "JTAG_DBP_CPU_GTL_TCK")
	)
	(segment
		(start 345.743784 -33.913826)
		(end 343.279222 -36.378388)
		(width 0.0889)
		(layer "F.Cu")
		(net "JTAG_DBP_CPU_GTL_TCK")
	)
	(segment
		(start 383.646934 -65.085468)
		(end 384.24993 -65.688464)
		(width 0.12954)
		(layer "F.Cu")
		(net "JTAG_DBP_CPU_GTL_TCK")
	)
	(segment
		(start 346.214446 -27.627834)
		(end 346.214446 -29.542994)
		(width 0.12954)
		(layer "F.Cu")
		(net "JTAG_DBP_CPU_GTL_TCK")
	)
	(segment
		(start 355.718872 -19.799554)
		(end 372.41988 -36.500562)
		(width 0.12954)
		(layer "F.Cu")
		(net "JTAG_DBP_CPU_GTL_TCK")
	)
	(segment
		(start 346.964254 -24.26208)
		(end 346.4052 -23.703026)
		(width 0.12954)
		(layer "F.Cu")
		(net "JTAG_DBP_CPU_GTL_TCK")
	)
	(segment
		(start 100.25888 -52.415948)
		(end 99.73818 -51.895248)
		(width 0.12954)
		(layer "F.Cu")
		(net "JTAG_DBP_CPU_GTL_TCK")
	)
	(segment
		(start 343.403174 -38.518084)
		(end 343.403174 -38.880034)
		(width 0.0889)
		(layer "F.Cu")
		(net "JTAG_DBP_CPU_GTL_TCK")
	)
	(segment
		(start 346.355416 -27.287474)
		(end 346.214446 -27.627834)
		(width 0.12954)
		(layer "F.Cu")
		(net "JTAG_DBP_CPU_GTL_TCK")
	)
	(segment
		(start 346.4052 -23.703026)
		(end 346.4052 -20.691094)
		(width 0.12954)
		(layer "F.Cu")
		(net "JTAG_DBP_CPU_GTL_TCK")
	)
	(segment
		(start 372.41988 -36.769802)
		(end 374.93448 -39.284402)
		(width 0.12954)
		(layer "F.Cu")
		(net "JTAG_DBP_CPU_GTL_TCK")
	)
	(segment
		(start 346.464636 -27.178254)
		(end 346.355416 -27.287474)
		(width 0.12954)
		(layer "F.Cu")
		(net "JTAG_DBP_CPU_GTL_TCK")
	)
	(segment
		(start 381.18288 -63.617348)
		(end 382.1811 -64.615568)
		(width 0.12954)
		(layer "F.Cu")
		(net "JTAG_DBP_CPU_GTL_TCK")
	)
	(segment
		(start 346.214446 -29.542994)
		(end 345.743784 -30.013656)
		(width 0.12954)
		(layer "F.Cu")
		(net "JTAG_DBP_CPU_GTL_TCK")
	)
	(segment
		(start 346.964254 -24.26208)
		(end 346.464636 -24.761698)
		(width 0.12954)
		(layer "F.Cu")
		(net "JTAG_DBP_CPU_GTL_TCK")
	)
	(segment
		(start 346.4052 -20.691094)
		(end 347.29674 -19.799554)
		(width 0.12954)
		(layer "F.Cu")
		(net "JTAG_DBP_CPU_GTL_TCK")
	)
	(segment
		(start 343.403174 -38.880034)
		(end 343.40292 -38.880288)
		(width 0.0889)
		(layer "F.Cu")
		(net "JTAG_DBP_CPU_GTL_TCK")
	)
	(segment
		(start 345.743784 -30.013656)
		(end 345.743784 -33.913826)
		(width 0.12954)
		(layer "F.Cu")
		(net "JTAG_DBP_CPU_GTL_TCK")
	)
	(segment
		(start 99.73818 -51.895248)
		(end 97.33153 -51.895248)
		(width 0.12954)
		(layer "F.Cu")
		(net "JTAG_DBP_CPU_GTL_TCK")
	)
	(segment
		(start 384.24993 -65.688464)
		(end 385.316222 -65.688464)
		(width 0.12954)
		(layer "F.Cu")
		(net "JTAG_DBP_CPU_GTL_TCK")
	)
	(segment
		(start 372.41988 -36.500562)
		(end 372.41988 -36.769802)
		(width 0.12954)
		(layer "F.Cu")
		(net "JTAG_DBP_CPU_GTL_TCK")
	)
	(via
		(at 120.13184 -152.946608)
		(size 0.508)
		(drill 0.254)
		(layers "F.Cu" "B.Cu")
		(net "JTAG_DBP_CPU_GTL_TCK")
	)
	(via
		(at 264.40638 -32.596328)
		(size 0.508)
		(drill 0.254)
		(layers "F.Cu" "B.Cu")
		(net "JTAG_DBP_CPU_GTL_TCK")
	)
	(via
		(at 264.98804 -152.723088)
		(size 0.508)
		(drill 0.254)
		(layers "F.Cu" "B.Cu")
		(net "JTAG_DBP_CPU_GTL_TCK")
	)
	(via
		(at 121.54154 -153.147268)
		(size 0.508)
		(drill 0.254)
		(layers "F.Cu" "B.Cu")
		(net "JTAG_DBP_CPU_GTL_TCK")
	)
	(via
		(at 100.25888 -52.415948)
		(size 0.508)
		(drill 0.254)
		(layers "F.Cu" "B.Cu")
		(net "JTAG_DBP_CPU_GTL_TCK")
	)
	(via
		(at 215.30564 -28.946348)
		(size 0.508)
		(drill 0.254)
		(layers "F.Cu" "B.Cu")
		(net "JTAG_DBP_CPU_GTL_TCK")
	)
	(via
		(at 382.1811 -64.615568)
		(size 0.508)
		(drill 0.254)
		(layers "F.Cu" "B.Cu")
		(net "JTAG_DBP_CPU_GTL_TCK")
	)
	(segment
		(start 216.91981 -37.352478)
		(end 215.626188 -36.058856)
		(width 0.12954)
		(layer "B.Cu")
		(net "JTAG_DBP_CPU_GTL_TCK")
	)
	(segment
		(start 246.797576 -43.170348)
		(end 242.32108 -43.170348)
		(width 0.12954)
		(layer "B.Cu")
		(net "JTAG_DBP_CPU_GTL_TCK")
	)
	(segment
		(start 88.1253 -187.645548)
		(end 88.1253 -189.911228)
		(width 0.12954)
		(layer "B.Cu")
		(net "JTAG_DBP_CPU_GTL_TCK")
	)
	(segment
		(start 236.303058 -42.586148)
		(end 232.913682 -41.18229)
		(width 0.12954)
		(layer "B.Cu")
		(net "JTAG_DBP_CPU_GTL_TCK")
	)
	(segment
		(start 232.913682 -41.18229)
		(end 230.09987 -38.368478)
		(width 0.12954)
		(layer "B.Cu")
		(net "JTAG_DBP_CPU_GTL_TCK")
	)
	(segment
		(start 265.333988 -153.54046)
		(end 265.333988 -157.145736)
		(width 0.12954)
		(layer "B.Cu")
		(net "JTAG_DBP_CPU_GTL_TCK")
	)
	(segment
		(start 87.731346 -190.305182)
		(end 87.489284 -190.305182)
		(width 0.12954)
		(layer "B.Cu")
		(net "JTAG_DBP_CPU_GTL_TCK")
	)
	(segment
		(start 259.598922 -39.049706)
		(end 256.902204 -39.049706)
		(width 0.12954)
		(layer "B.Cu")
		(net "JTAG_DBP_CPU_GTL_TCK")
	)
	(segment
		(start 265.333988 -157.145736)
		(end 277.335742 -169.14749)
		(width 0.12954)
		(layer "B.Cu")
		(net "JTAG_DBP_CPU_GTL_TCK")
	)
	(segment
		(start 87.48776 -189.318138)
		(end 87.489284 -189.319662)
		(width 0.12954)
		(layer "B.Cu")
		(net "JTAG_DBP_CPU_GTL_TCK")
	)
	(segment
		(start 221.435422 -37.352478)
		(end 216.91981 -37.352478)
		(width 0.12954)
		(layer "B.Cu")
		(net "JTAG_DBP_CPU_GTL_TCK")
	)
	(segment
		(start 325.533258 -187.84824)
		(end 325.322438 -188.05906)
		(width 0.12954)
		(layer "B.Cu")
		(net "JTAG_DBP_CPU_GTL_TCK")
	)
	(segment
		(start 87.46744 -176.888648)
		(end 87.46744 -186.987688)
		(width 0.12954)
		(layer "B.Cu")
		(net "JTAG_DBP_CPU_GTL_TCK")
	)
	(segment
		(start 253.439422 -41.008554)
		(end 248.95937 -41.008554)
		(width 0.12954)
		(layer "B.Cu")
		(net "JTAG_DBP_CPU_GTL_TCK")
	)
	(segment
		(start 260.369812 -38.278816)
		(end 259.598922 -39.049706)
		(width 0.12954)
		(layer "B.Cu")
		(net "JTAG_DBP_CPU_GTL_TCK")
	)
	(segment
		(start 215.626188 -29.266896)
		(end 215.30564 -28.946348)
		(width 0.12954)
		(layer "B.Cu")
		(net "JTAG_DBP_CPU_GTL_TCK")
	)
	(segment
		(start 86.821772 -187.338716)
		(end 86.989158 -187.506102)
		(width 0.12954)
		(layer "B.Cu")
		(net "JTAG_DBP_CPU_GTL_TCK")
	)
	(segment
		(start 119.68226 -154.399488)
		(end 109.9566 -154.399488)
		(width 0.12954)
		(layer "B.Cu")
		(net "JTAG_DBP_CPU_GTL_TCK")
	)
	(segment
		(start 241.73688 -42.586148)
		(end 236.303058 -42.586148)
		(width 0.12954)
		(layer "B.Cu")
		(net "JTAG_DBP_CPU_GTL_TCK")
	)
	(segment
		(start 325.533258 -185.188606)
		(end 325.533258 -187.84824)
		(width 0.12954)
		(layer "B.Cu")
		(net "JTAG_DBP_CPU_GTL_TCK")
	)
	(segment
		(start 121.54154 -153.147268)
		(end 120.93448 -153.147268)
		(width 0.12954)
		(layer "B.Cu")
		(net "JTAG_DBP_CPU_GTL_TCK")
	)
	(segment
		(start 264.98804 -152.723088)
		(end 264.98804 -153.194512)
		(width 0.12954)
		(layer "B.Cu")
		(net "JTAG_DBP_CPU_GTL_TCK")
	)
	(segment
		(start 109.9566 -154.399488)
		(end 87.46744 -176.888648)
		(width 0.12954)
		(layer "B.Cu")
		(net "JTAG_DBP_CPU_GTL_TCK")
	)
	(segment
		(start 248.95937 -41.008554)
		(end 246.797576 -43.170348)
		(width 0.12954)
		(layer "B.Cu")
		(net "JTAG_DBP_CPU_GTL_TCK")
	)
	(segment
		(start 260.369812 -36.632896)
		(end 260.369812 -38.278816)
		(width 0.12954)
		(layer "B.Cu")
		(net "JTAG_DBP_CPU_GTL_TCK")
	)
	(segment
		(start 87.46744 -186.987688)
		(end 88.1253 -187.645548)
		(width 0.12954)
		(layer "B.Cu")
		(net "JTAG_DBP_CPU_GTL_TCK")
	)
	(segment
		(start 88.1253 -189.911228)
		(end 87.731346 -190.305182)
		(width 0.12954)
		(layer "B.Cu")
		(net "JTAG_DBP_CPU_GTL_TCK")
	)
	(segment
		(start 254.313436 -40.13454)
		(end 253.439422 -41.008554)
		(width 0.12954)
		(layer "B.Cu")
		(net "JTAG_DBP_CPU_GTL_TCK")
	)
	(segment
		(start 264.40638 -32.596328)
		(end 260.369812 -36.632896)
		(width 0.12954)
		(layer "B.Cu")
		(net "JTAG_DBP_CPU_GTL_TCK")
	)
	(segment
		(start 110.10011 -153.383234)
		(end 86.821772 -176.661572)
		(width 0.12954)
		(layer "B.Cu")
		(net "JTAG_DBP_CPU_GTL_TCK")
	)
	(segment
		(start 277.335742 -169.14749)
		(end 309.492142 -169.14749)
		(width 0.12954)
		(layer "B.Cu")
		(net "JTAG_DBP_CPU_GTL_TCK")
	)
	(segment
		(start 87.489284 -189.319662)
		(end 87.489284 -190.305182)
		(width 0.12954)
		(layer "B.Cu")
		(net "JTAG_DBP_CPU_GTL_TCK")
	)
	(segment
		(start 256.902204 -39.049706)
		(end 255.81737 -40.13454)
		(width 0.12954)
		(layer "B.Cu")
		(net "JTAG_DBP_CPU_GTL_TCK")
	)
	(segment
		(start 222.451422 -38.368478)
		(end 221.435422 -37.352478)
		(width 0.12954)
		(layer "B.Cu")
		(net "JTAG_DBP_CPU_GTL_TCK")
	)
	(segment
		(start 86.989158 -187.506102)
		(end 86.989158 -188.819536)
		(width 0.12954)
		(layer "B.Cu")
		(net "JTAG_DBP_CPU_GTL_TCK")
	)
	(segment
		(start 215.626188 -36.058856)
		(end 215.626188 -29.266896)
		(width 0.12954)
		(layer "B.Cu")
		(net "JTAG_DBP_CPU_GTL_TCK")
	)
	(segment
		(start 120.93448 -153.147268)
		(end 119.68226 -154.399488)
		(width 0.12954)
		(layer "B.Cu")
		(net "JTAG_DBP_CPU_GTL_TCK")
	)
	(segment
		(start 242.32108 -43.170348)
		(end 241.73688 -42.586148)
		(width 0.12954)
		(layer "B.Cu")
		(net "JTAG_DBP_CPU_GTL_TCK")
	)
	(segment
		(start 120.13184 -152.946608)
		(end 119.695214 -153.383234)
		(width 0.12954)
		(layer "B.Cu")
		(net "JTAG_DBP_CPU_GTL_TCK")
	)
	(segment
		(start 119.695214 -153.383234)
		(end 110.10011 -153.383234)
		(width 0.12954)
		(layer "B.Cu")
		(net "JTAG_DBP_CPU_GTL_TCK")
	)
	(segment
		(start 86.989158 -188.819536)
		(end 87.48776 -189.318138)
		(width 0.12954)
		(layer "B.Cu")
		(net "JTAG_DBP_CPU_GTL_TCK")
	)
	(segment
		(start 86.821772 -176.661572)
		(end 86.821772 -187.338716)
		(width 0.12954)
		(layer "B.Cu")
		(net "JTAG_DBP_CPU_GTL_TCK")
	)
	(segment
		(start 309.492142 -169.14749)
		(end 325.533258 -185.188606)
		(width 0.12954)
		(layer "B.Cu")
		(net "JTAG_DBP_CPU_GTL_TCK")
	)
	(segment
		(start 230.09987 -38.368478)
		(end 222.451422 -38.368478)
		(width 0.12954)
		(layer "B.Cu")
		(net "JTAG_DBP_CPU_GTL_TCK")
	)
	(segment
		(start 255.81737 -40.13454)
		(end 254.313436 -40.13454)
		(width 0.12954)
		(layer "B.Cu")
		(net "JTAG_DBP_CPU_GTL_TCK")
	)
	(segment
		(start 264.98804 -153.194512)
		(end 265.333988 -153.54046)
		(width 0.12954)
		(layer "B.Cu")
		(net "JTAG_DBP_CPU_GTL_TCK")
	)
	(segment
		(start 117.92204 -152.542748)
		(end 117.92204 -115.156488)
		(width 0.127)
		(layer "In2.Cu")
		(net "JTAG_DBP_CPU_GTL_TCK")
	)
	(segment
		(start 113.9444 -103.137208)
		(end 113.9444 -90.795348)
		(width 0.127)
		(layer "In2.Cu")
		(net "JTAG_DBP_CPU_GTL_TCK")
	)
	(segment
		(start 117.29212 -104.841548)
		(end 116.77396 -104.323388)
		(width 0.127)
		(layer "In2.Cu")
		(net "JTAG_DBP_CPU_GTL_TCK")
	)
	(segment
		(start 116.77396 -104.323388)
		(end 115.13058 -104.323388)
		(width 0.127)
		(layer "In2.Cu")
		(net "JTAG_DBP_CPU_GTL_TCK")
	)
	(segment
		(start 107.6198 -58.791348)
		(end 106.35488 -57.526428)
		(width 0.127)
		(layer "In2.Cu")
		(net "JTAG_DBP_CPU_GTL_TCK")
	)
	(segment
		(start 106.35488 -56.650128)
		(end 102.1207 -52.415948)
		(width 0.127)
		(layer "In2.Cu")
		(net "JTAG_DBP_CPU_GTL_TCK")
	)
	(segment
		(start 115.13058 -104.323388)
		(end 113.9444 -103.137208)
		(width 0.127)
		(layer "In2.Cu")
		(net "JTAG_DBP_CPU_GTL_TCK")
	)
	(segment
		(start 112.649 -86.502748)
		(end 107.6198 -81.473548)
		(width 0.127)
		(layer "In2.Cu")
		(net "JTAG_DBP_CPU_GTL_TCK")
	)
	(segment
		(start 107.6198 -81.473548)
		(end 107.6198 -58.791348)
		(width 0.127)
		(layer "In2.Cu")
		(net "JTAG_DBP_CPU_GTL_TCK")
	)
	(segment
		(start 117.92204 -115.156488)
		(end 116.731034 -113.965482)
		(width 0.127)
		(layer "In2.Cu")
		(net "JTAG_DBP_CPU_GTL_TCK")
	)
	(segment
		(start 116.731034 -113.965482)
		(end 116.731034 -106.901742)
		(width 0.127)
		(layer "In2.Cu")
		(net "JTAG_DBP_CPU_GTL_TCK")
	)
	(segment
		(start 120.13184 -152.946608)
		(end 119.7737 -153.304748)
		(width 0.127)
		(layer "In2.Cu")
		(net "JTAG_DBP_CPU_GTL_TCK")
	)
	(segment
		(start 117.29212 -106.340656)
		(end 117.29212 -104.841548)
		(width 0.127)
		(layer "In2.Cu")
		(net "JTAG_DBP_CPU_GTL_TCK")
	)
	(segment
		(start 118.68404 -153.304748)
		(end 117.92204 -152.542748)
		(width 0.127)
		(layer "In2.Cu")
		(net "JTAG_DBP_CPU_GTL_TCK")
	)
	(segment
		(start 119.7737 -153.304748)
		(end 118.68404 -153.304748)
		(width 0.127)
		(layer "In2.Cu")
		(net "JTAG_DBP_CPU_GTL_TCK")
	)
	(segment
		(start 112.649 -89.499948)
		(end 112.649 -86.502748)
		(width 0.127)
		(layer "In2.Cu")
		(net "JTAG_DBP_CPU_GTL_TCK")
	)
	(segment
		(start 102.1207 -52.415948)
		(end 100.25888 -52.415948)
		(width 0.127)
		(layer "In2.Cu")
		(net "JTAG_DBP_CPU_GTL_TCK")
	)
	(segment
		(start 106.35488 -57.526428)
		(end 106.35488 -56.650128)
		(width 0.127)
		(layer "In2.Cu")
		(net "JTAG_DBP_CPU_GTL_TCK")
	)
	(segment
		(start 113.9444 -90.795348)
		(end 112.649 -89.499948)
		(width 0.127)
		(layer "In2.Cu")
		(net "JTAG_DBP_CPU_GTL_TCK")
	)
	(segment
		(start 116.731034 -106.901742)
		(end 117.29212 -106.340656)
		(width 0.127)
		(layer "In2.Cu")
		(net "JTAG_DBP_CPU_GTL_TCK")
	)
	(segment
		(start 179.750212 -16.65986)
		(end 189.621414 -16.65986)
		(width 0.127)
		(layer "In4.Cu")
		(net "JTAG_DBP_CPU_GTL_TCK")
	)
	(segment
		(start 264.530586 -32.296862)
		(end 264.40638 -32.596328)
		(width 0.127)
		(layer "In4.Cu")
		(net "JTAG_DBP_CPU_GTL_TCK")
	)
	(segment
		(start 189.621414 -16.65986)
		(end 190.376302 -17.414748)
		(width 0.127)
		(layer "In4.Cu")
		(net "JTAG_DBP_CPU_GTL_TCK")
	)
	(segment
		(start 207.543146 -18.899632)
		(end 210.667092 -23.57501)
		(width 0.127)
		(layer "In4.Cu")
		(net "JTAG_DBP_CPU_GTL_TCK")
	)
	(segment
		(start 140.283946 -32.070548)
		(end 150.051516 -22.302978)
		(width 0.127)
		(layer "In4.Cu")
		(net "JTAG_DBP_CPU_GTL_TCK")
	)
	(segment
		(start 100.25888 -52.415948)
		(end 101.88448 -54.041548)
		(width 0.127)
		(layer "In4.Cu")
		(net "JTAG_DBP_CPU_GTL_TCK")
	)
	(segment
		(start 212.20176 -26.312368)
		(end 212.20176 -28.204922)
		(width 0.127)
		(layer "In4.Cu")
		(net "JTAG_DBP_CPU_GTL_TCK")
	)
	(segment
		(start 194.583558 -17.414748)
		(end 195.825618 -16.172688)
		(width 0.127)
		(layer "In4.Cu")
		(net "JTAG_DBP_CPU_GTL_TCK")
	)
	(segment
		(start 162.6362 -17.788128)
		(end 163.26612 -17.158208)
		(width 0.127)
		(layer "In4.Cu")
		(net "JTAG_DBP_CPU_GTL_TCK")
	)
	(segment
		(start 311.91073 -14.343888)
		(end 303.25822 -17.927828)
		(width 0.127)
		(layer "In4.Cu")
		(net "JTAG_DBP_CPU_GTL_TCK")
	)
	(segment
		(start 295.486074 -19.473926)
		(end 264.530586 -32.296862)
		(width 0.127)
		(layer "In4.Cu")
		(net "JTAG_DBP_CPU_GTL_TCK")
	)
	(segment
		(start 213.31301 -28.574238)
		(end 213.68512 -28.946348)
		(width 0.127)
		(layer "In4.Cu")
		(net "JTAG_DBP_CPU_GTL_TCK")
	)
	(segment
		(start 150.051516 -22.302978)
		(end 151.341836 -22.302978)
		(width 0.127)
		(layer "In4.Cu")
		(net "JTAG_DBP_CPU_GTL_TCK")
	)
	(segment
		(start 160.49244 -20.645628)
		(end 162.6362 -18.501868)
		(width 0.127)
		(layer "In4.Cu")
		(net "JTAG_DBP_CPU_GTL_TCK")
	)
	(segment
		(start 151.341836 -22.302978)
		(end 152.999186 -20.645628)
		(width 0.127)
		(layer "In4.Cu")
		(net "JTAG_DBP_CPU_GTL_TCK")
	)
	(segment
		(start 171.816014 -16.421608)
		(end 179.51196 -16.421608)
		(width 0.127)
		(layer "In4.Cu")
		(net "JTAG_DBP_CPU_GTL_TCK")
	)
	(segment
		(start 381.80137 -50.327052)
		(end 378.074428 -45.30217)
		(width 0.127)
		(layer "In4.Cu")
		(net "JTAG_DBP_CPU_GTL_TCK")
	)
	(segment
		(start 213.68512 -28.946348)
		(end 215.30564 -28.946348)
		(width 0.127)
		(layer "In4.Cu")
		(net "JTAG_DBP_CPU_GTL_TCK")
	)
	(segment
		(start 204.816202 -16.172688)
		(end 207.543146 -18.899632)
		(width 0.127)
		(layer "In4.Cu")
		(net "JTAG_DBP_CPU_GTL_TCK")
	)
	(segment
		(start 384.57632 -64.615568)
		(end 385.30022 -63.891668)
		(width 0.127)
		(layer "In4.Cu")
		(net "JTAG_DBP_CPU_GTL_TCK")
	)
	(segment
		(start 378.074428 -45.30217)
		(end 370.181124 -35.683444)
		(width 0.127)
		(layer "In4.Cu")
		(net "JTAG_DBP_CPU_GTL_TCK")
	)
	(segment
		(start 385.30022 -63.891668)
		(end 385.30022 -58.36539)
		(width 0.127)
		(layer "In4.Cu")
		(net "JTAG_DBP_CPU_GTL_TCK")
	)
	(segment
		(start 112.09274 -45.485558)
		(end 125.50775 -32.070548)
		(width 0.127)
		(layer "In4.Cu")
		(net "JTAG_DBP_CPU_GTL_TCK")
	)
	(segment
		(start 162.6362 -18.501868)
		(end 162.6362 -17.788128)
		(width 0.127)
		(layer "In4.Cu")
		(net "JTAG_DBP_CPU_GTL_TCK")
	)
	(segment
		(start 211.517738 -25.628346)
		(end 212.20176 -26.312368)
		(width 0.127)
		(layer "In4.Cu")
		(net "JTAG_DBP_CPU_GTL_TCK")
	)
	(segment
		(start 190.376302 -17.414748)
		(end 194.583558 -17.414748)
		(width 0.127)
		(layer "In4.Cu")
		(net "JTAG_DBP_CPU_GTL_TCK")
	)
	(segment
		(start 171.079414 -17.158208)
		(end 171.816014 -16.421608)
		(width 0.127)
		(layer "In4.Cu")
		(net "JTAG_DBP_CPU_GTL_TCK")
	)
	(segment
		(start 321.239896 -14.054328)
		(end 320.950336 -14.343888)
		(width 0.127)
		(layer "In4.Cu")
		(net "JTAG_DBP_CPU_GTL_TCK")
	)
	(segment
		(start 382.1811 -64.615568)
		(end 384.57632 -64.615568)
		(width 0.127)
		(layer "In4.Cu")
		(net "JTAG_DBP_CPU_GTL_TCK")
	)
	(segment
		(start 303.25822 -17.927828)
		(end 295.486074 -19.473926)
		(width 0.127)
		(layer "In4.Cu")
		(net "JTAG_DBP_CPU_GTL_TCK")
	)
	(segment
		(start 384.308604 -53.382164)
		(end 381.80137 -50.327052)
		(width 0.127)
		(layer "In4.Cu")
		(net "JTAG_DBP_CPU_GTL_TCK")
	)
	(segment
		(start 101.88448 -54.041548)
		(end 110.94212 -54.041548)
		(width 0.127)
		(layer "In4.Cu")
		(net "JTAG_DBP_CPU_GTL_TCK")
	)
	(segment
		(start 179.51196 -16.421608)
		(end 179.750212 -16.65986)
		(width 0.127)
		(layer "In4.Cu")
		(net "JTAG_DBP_CPU_GTL_TCK")
	)
	(segment
		(start 212.20176 -28.204922)
		(end 212.571076 -28.574238)
		(width 0.127)
		(layer "In4.Cu")
		(net "JTAG_DBP_CPU_GTL_TCK")
	)
	(segment
		(start 320.950336 -14.343888)
		(end 311.91073 -14.343888)
		(width 0.127)
		(layer "In4.Cu")
		(net "JTAG_DBP_CPU_GTL_TCK")
	)
	(segment
		(start 195.825618 -16.172688)
		(end 204.816202 -16.172688)
		(width 0.127)
		(layer "In4.Cu")
		(net "JTAG_DBP_CPU_GTL_TCK")
	)
	(segment
		(start 112.09274 -52.890928)
		(end 112.09274 -45.485558)
		(width 0.127)
		(layer "In4.Cu")
		(net "JTAG_DBP_CPU_GTL_TCK")
	)
	(segment
		(start 212.571076 -28.574238)
		(end 213.31301 -28.574238)
		(width 0.127)
		(layer "In4.Cu")
		(net "JTAG_DBP_CPU_GTL_TCK")
	)
	(segment
		(start 110.94212 -54.041548)
		(end 112.09274 -52.890928)
		(width 0.127)
		(layer "In4.Cu")
		(net "JTAG_DBP_CPU_GTL_TCK")
	)
	(segment
		(start 163.26612 -17.158208)
		(end 171.079414 -17.158208)
		(width 0.127)
		(layer "In4.Cu")
		(net "JTAG_DBP_CPU_GTL_TCK")
	)
	(segment
		(start 370.181124 -35.683444)
		(end 348.800928 -14.303248)
		(width 0.127)
		(layer "In4.Cu")
		(net "JTAG_DBP_CPU_GTL_TCK")
	)
	(segment
		(start 125.50775 -32.070548)
		(end 140.283946 -32.070548)
		(width 0.127)
		(layer "In4.Cu")
		(net "JTAG_DBP_CPU_GTL_TCK")
	)
	(segment
		(start 152.999186 -20.645628)
		(end 160.49244 -20.645628)
		(width 0.127)
		(layer "In4.Cu")
		(net "JTAG_DBP_CPU_GTL_TCK")
	)
	(segment
		(start 341.014304 -14.054328)
		(end 321.239896 -14.054328)
		(width 0.127)
		(layer "In4.Cu")
		(net "JTAG_DBP_CPU_GTL_TCK")
	)
	(segment
		(start 385.30022 -58.36539)
		(end 384.308604 -53.382164)
		(width 0.127)
		(layer "In4.Cu")
		(net "JTAG_DBP_CPU_GTL_TCK")
	)
	(segment
		(start 210.667092 -23.57501)
		(end 211.517738 -25.628346)
		(width 0.127)
		(layer "In4.Cu")
		(net "JTAG_DBP_CPU_GTL_TCK")
	)
	(segment
		(start 341.263224 -14.303248)
		(end 341.014304 -14.054328)
		(width 0.127)
		(layer "In4.Cu")
		(net "JTAG_DBP_CPU_GTL_TCK")
	)
	(segment
		(start 348.800928 -14.303248)
		(end 341.263224 -14.303248)
		(width 0.127)
		(layer "In4.Cu")
		(net "JTAG_DBP_CPU_GTL_TCK")
	)
	(segment
		(start 137.26922 -151.811228)
		(end 140.10894 -151.811228)
		(width 0.127)
		(layer "In13.Cu")
		(net "JTAG_DBP_CPU_GTL_TCK")
	)
	(segment
		(start 121.54154 -153.147268)
		(end 122.91822 -151.770588)
		(width 0.127)
		(layer "In13.Cu")
		(net "JTAG_DBP_CPU_GTL_TCK")
	)
	(segment
		(start 217.12174 -155.522168)
		(end 262.72998 -155.522168)
		(width 0.127)
		(layer "In13.Cu")
		(net "JTAG_DBP_CPU_GTL_TCK")
	)
	(segment
		(start 146.00174 -146.106388)
		(end 150.28926 -150.393908)
		(width 0.127)
		(layer "In13.Cu")
		(net "JTAG_DBP_CPU_GTL_TCK")
	)
	(segment
		(start 208.48066 -164.163248)
		(end 217.12174 -155.522168)
		(width 0.127)
		(layer "In13.Cu")
		(net "JTAG_DBP_CPU_GTL_TCK")
	)
	(segment
		(start 150.28926 -150.393908)
		(end 170.696128 -150.393908)
		(width 0.127)
		(layer "In13.Cu")
		(net "JTAG_DBP_CPU_GTL_TCK")
	)
	(segment
		(start 135.30834 -151.270208)
		(end 136.7282 -151.270208)
		(width 0.127)
		(layer "In13.Cu")
		(net "JTAG_DBP_CPU_GTL_TCK")
	)
	(segment
		(start 182.87746 -163.5506)
		(end 183.490108 -164.163248)
		(width 0.127)
		(layer "In13.Cu")
		(net "JTAG_DBP_CPU_GTL_TCK")
	)
	(segment
		(start 144.28978 -146.106388)
		(end 146.00174 -146.106388)
		(width 0.127)
		(layer "In13.Cu")
		(net "JTAG_DBP_CPU_GTL_TCK")
	)
	(segment
		(start 183.490108 -164.163248)
		(end 208.48066 -164.163248)
		(width 0.127)
		(layer "In13.Cu")
		(net "JTAG_DBP_CPU_GTL_TCK")
	)
	(segment
		(start 170.696128 -150.393908)
		(end 182.87746 -162.57524)
		(width 0.127)
		(layer "In13.Cu")
		(net "JTAG_DBP_CPU_GTL_TCK")
	)
	(segment
		(start 182.87746 -162.57524)
		(end 182.87746 -163.5506)
		(width 0.127)
		(layer "In13.Cu")
		(net "JTAG_DBP_CPU_GTL_TCK")
	)
	(segment
		(start 136.7282 -151.270208)
		(end 137.26922 -151.811228)
		(width 0.127)
		(layer "In13.Cu")
		(net "JTAG_DBP_CPU_GTL_TCK")
	)
	(segment
		(start 264.98804 -153.264108)
		(end 264.98804 -152.723088)
		(width 0.127)
		(layer "In13.Cu")
		(net "JTAG_DBP_CPU_GTL_TCK")
	)
	(segment
		(start 143.4465 -148.473668)
		(end 143.4465 -146.949668)
		(width 0.127)
		(layer "In13.Cu")
		(net "JTAG_DBP_CPU_GTL_TCK")
	)
	(segment
		(start 143.4465 -146.949668)
		(end 144.28978 -146.106388)
		(width 0.127)
		(layer "In13.Cu")
		(net "JTAG_DBP_CPU_GTL_TCK")
	)
	(segment
		(start 134.80796 -151.770588)
		(end 135.30834 -151.270208)
		(width 0.127)
		(layer "In13.Cu")
		(net "JTAG_DBP_CPU_GTL_TCK")
	)
	(segment
		(start 122.91822 -151.770588)
		(end 134.80796 -151.770588)
		(width 0.127)
		(layer "In13.Cu")
		(net "JTAG_DBP_CPU_GTL_TCK")
	)
	(segment
		(start 262.72998 -155.522168)
		(end 264.98804 -153.264108)
		(width 0.127)
		(layer "In13.Cu")
		(net "JTAG_DBP_CPU_GTL_TCK")
	)
	(segment
		(start 140.10894 -151.811228)
		(end 143.4465 -148.473668)
		(width 0.127)
		(layer "In13.Cu")
		(net "JTAG_DBP_CPU_GTL_TCK")
	)
	(segment
		(start 110.230666 -233.87812)
		(end 110.230666 -233.34218)
		(width 0.12954)
		(layer "F.Cu")
		(net "JTAG_DBP_CPU1_QS_GTL_R_TMS")
	)
	(via
		(at 110.230666 -233.34218)
		(size 0.4572)
		(drill 0.2032)
		(layers "F.Cu" "B.Cu")
		(net "JTAG_DBP_CPU1_QS_GTL_R_TMS")
	)
	(via
		(at 86.021418 -196.202808)
		(size 0.508)
		(drill 0.254)
		(layers "F.Cu" "B.Cu")
		(net "JTAG_DBP_CPU1_QS_GTL_R_TMS")
	)
	(segment
		(start 86.021418 -191.557148)
		(end 86.473284 -191.105282)
		(width 0.12954)
		(layer "B.Cu")
		(net "JTAG_DBP_CPU1_QS_GTL_R_TMS")
	)
	(segment
		(start 90.399616 -224.373948)
		(end 90.399616 -224.389442)
		(width 0.0889)
		(layer "B.Cu")
		(net "JTAG_DBP_CPU1_QS_GTL_R_TMS")
	)
	(segment
		(start 85.057996 -223.891348)
		(end 85.043264 -223.899984)
		(width 0.0889)
		(layer "B.Cu")
		(net "JTAG_DBP_CPU1_QS_GTL_R_TMS")
	)
	(segment
		(start 110.043468 -233.666538)
		(end 110.034578 -233.661458)
		(width 0.0889)
		(layer "B.Cu")
		(net "JTAG_DBP_CPU1_QS_GTL_R_TMS")
	)
	(segment
		(start 97.739454 -224.70872)
		(end 97.730564 -224.7138)
		(width 0.0889)
		(layer "B.Cu")
		(net "JTAG_DBP_CPU1_QS_GTL_R_TMS")
	)
	(segment
		(start 96.038416 -224.373948)
		(end 96.038416 -224.389442)
		(width 0.0889)
		(layer "B.Cu")
		(net "JTAG_DBP_CPU1_QS_GTL_R_TMS")
	)
	(segment
		(start 103.747316 -226.017328)
		(end 103.747316 -226.003104)
		(width 0.0889)
		(layer "B.Cu")
		(net "JTAG_DBP_CPU1_QS_GTL_R_TMS")
	)
	(segment
		(start 97.168716 -224.389442)
		(end 97.168716 -224.379536)
		(width 0.0889)
		(layer "B.Cu")
		(net "JTAG_DBP_CPU1_QS_GTL_R_TMS")
	)
	(segment
		(start 108.915962 -231.714548)
		(end 108.915962 -231.69245)
		(width 0.0889)
		(layer "B.Cu")
		(net "JTAG_DBP_CPU1_QS_GTL_R_TMS")
	)
	(segment
		(start 99.048316 -224.389442)
		(end 99.048316 -224.379536)
		(width 0.0889)
		(layer "B.Cu")
		(net "JTAG_DBP_CPU1_QS_GTL_R_TMS")
	)
	(segment
		(start 104.217216 -226.831144)
		(end 104.217216 -226.821238)
		(width 0.0889)
		(layer "B.Cu")
		(net "JTAG_DBP_CPU1_QS_GTL_R_TMS")
	)
	(segment
		(start 84.459318 -206.80807)
		(end 84.459318 -202.50277)
		(width 0.12954)
		(layer "B.Cu")
		(net "JTAG_DBP_CPU1_QS_GTL_R_TMS")
	)
	(segment
		(start 107.506262 -230.909114)
		(end 107.506262 -230.884984)
		(width 0.0889)
		(layer "B.Cu")
		(net "JTAG_DBP_CPU1_QS_GTL_R_TMS")
	)
	(segment
		(start 100.927916 -224.389442)
		(end 100.927916 -224.379536)
		(width 0.0889)
		(layer "B.Cu")
		(net "JTAG_DBP_CPU1_QS_GTL_R_TMS")
	)
	(segment
		(start 106.754168 -229.597204)
		(end 106.745278 -229.592124)
		(width 0.0889)
		(layer "B.Cu")
		(net "JTAG_DBP_CPU1_QS_GTL_R_TMS")
	)
	(segment
		(start 103.464614 -225.527616)
		(end 103.455724 -225.522536)
		(width 0.0889)
		(layer "B.Cu")
		(net "JTAG_DBP_CPU1_QS_GTL_R_TMS")
	)
	(segment
		(start 103.934768 -226.341686)
		(end 103.925878 -226.336606)
		(width 0.0889)
		(layer "B.Cu")
		(net "JTAG_DBP_CPU1_QS_GTL_R_TMS")
	)
	(segment
		(start 109.579664 -232.856278)
		(end 109.573568 -232.852722)
		(width 0.0889)
		(layer "B.Cu")
		(net "JTAG_DBP_CPU1_QS_GTL_R_TMS")
	)
	(segment
		(start 84.856066 -223.95053)
		(end 84.658708 -223.95053)
		(width 0.0889)
		(layer "B.Cu")
		(net "JTAG_DBP_CPU1_QS_GTL_R_TMS")
	)
	(segment
		(start 100.645468 -223.899984)
		(end 100.635054 -223.893888)
		(width 0.0889)
		(layer "B.Cu")
		(net "JTAG_DBP_CPU1_QS_GTL_R_TMS")
	)
	(segment
		(start 109.103414 -232.038906)
		(end 109.094524 -232.033826)
		(width 0.0889)
		(layer "B.Cu")
		(net "JTAG_DBP_CPU1_QS_GTL_R_TMS")
	)
	(segment
		(start 93.980254 -224.70872)
		(end 93.971364 -224.7138)
		(width 0.0889)
		(layer "B.Cu")
		(net "JTAG_DBP_CPU1_QS_GTL_R_TMS")
	)
	(segment
		(start 89.837768 -224.7138)
		(end 89.828878 -224.70872)
		(width 0.0889)
		(layer "B.Cu")
		(net "JTAG_DBP_CPU1_QS_GTL_R_TMS")
	)
	(segment
		(start 99.619054 -224.70872)
		(end 99.610164 -224.7138)
		(width 0.0889)
		(layer "B.Cu")
		(net "JTAG_DBP_CPU1_QS_GTL_R_TMS")
	)
	(segment
		(start 84.658708 -223.95053)
		(end 84.154772 -223.446594)
		(width 0.0889)
		(layer "B.Cu")
		(net "JTAG_DBP_CPU1_QS_GTL_R_TMS")
	)
	(segment
		(start 81.665318 -220.064076)
		(end 81.665318 -209.60207)
		(width 0.12954)
		(layer "B.Cu")
		(net "JTAG_DBP_CPU1_QS_GTL_R_TMS")
	)
	(segment
		(start 110.38713 -233.613198)
		(end 110.366048 -233.691176)
		(width 0.0889)
		(layer "B.Cu")
		(net "JTAG_DBP_CPU1_QS_GTL_R_TMS")
	)
	(segment
		(start 106.284014 -228.783388)
		(end 106.269282 -228.774752)
		(width 0.0889)
		(layer "B.Cu")
		(net "JTAG_DBP_CPU1_QS_GTL_R_TMS")
	)
	(segment
		(start 93.409516 -224.389442)
		(end 93.409516 -224.379536)
		(width 0.0889)
		(layer "B.Cu")
		(net "JTAG_DBP_CPU1_QS_GTL_R_TMS")
	)
	(segment
		(start 95.289116 -224.389442)
		(end 95.289116 -224.379536)
		(width 0.0889)
		(layer "B.Cu")
		(net "JTAG_DBP_CPU1_QS_GTL_R_TMS")
	)
	(segment
		(start 84.459318 -202.50277)
		(end 86.021418 -200.94067)
		(width 0.12954)
		(layer "B.Cu")
		(net "JTAG_DBP_CPU1_QS_GTL_R_TMS")
	)
	(segment
		(start 95.476568 -224.7138)
		(end 95.467678 -224.70872)
		(width 0.0889)
		(layer "B.Cu")
		(net "JTAG_DBP_CPU1_QS_GTL_R_TMS")
	)
	(segment
		(start 107.036616 -230.095298)
		(end 107.036616 -230.076756)
		(width 0.0889)
		(layer "B.Cu")
		(net "JTAG_DBP_CPU1_QS_GTL_R_TMS")
	)
	(segment
		(start 101.498654 -224.70872)
		(end 101.489764 -224.7138)
		(width 0.0889)
		(layer "B.Cu")
		(net "JTAG_DBP_CPU1_QS_GTL_R_TMS")
	)
	(segment
		(start 109.573568 -232.852722)
		(end 109.564678 -232.847642)
		(width 0.0889)
		(layer "B.Cu")
		(net "JTAG_DBP_CPU1_QS_GTL_R_TMS")
	)
	(segment
		(start 91.717368 -224.7138)
		(end 91.708478 -224.70872)
		(width 0.0889)
		(layer "B.Cu")
		(net "JTAG_DBP_CPU1_QS_GTL_R_TMS")
	)
	(segment
		(start 109.10951 -232.042462)
		(end 109.103414 -232.038906)
		(width 0.0889)
		(layer "B.Cu")
		(net "JTAG_DBP_CPU1_QS_GTL_R_TMS")
	)
	(segment
		(start 93.127068 -223.899984)
		(end 93.116654 -223.893888)
		(width 0.0889)
		(layer "B.Cu")
		(net "JTAG_DBP_CPU1_QS_GTL_R_TMS")
	)
	(segment
		(start 104.687116 -227.64496)
		(end 104.687116 -227.635054)
		(width 0.0889)
		(layer "B.Cu")
		(net "JTAG_DBP_CPU1_QS_GTL_R_TMS")
	)
	(segment
		(start 95.006668 -223.899984)
		(end 94.996254 -223.893888)
		(width 0.0889)
		(layer "B.Cu")
		(net "JTAG_DBP_CPU1_QS_GTL_R_TMS")
	)
	(segment
		(start 86.021418 -196.202808)
		(end 86.021418 -191.557148)
		(width 0.12954)
		(layer "B.Cu")
		(net "JTAG_DBP_CPU1_QS_GTL_R_TMS")
	)
	(segment
		(start 93.596968 -224.7138)
		(end 93.588078 -224.70872)
		(width 0.0889)
		(layer "B.Cu")
		(net "JTAG_DBP_CPU1_QS_GTL_R_TMS")
	)
	(segment
		(start 103.277162 -225.203258)
		(end 103.277162 -225.187764)
		(width 0.0889)
		(layer "B.Cu")
		(net "JTAG_DBP_CPU1_QS_GTL_R_TMS")
	)
	(segment
		(start 92.279216 -224.373948)
		(end 92.279216 -224.389442)
		(width 0.0889)
		(layer "B.Cu")
		(net "JTAG_DBP_CPU1_QS_GTL_R_TMS")
	)
	(segment
		(start 94.158816 -224.373948)
		(end 94.158816 -224.389442)
		(width 0.0889)
		(layer "B.Cu")
		(net "JTAG_DBP_CPU1_QS_GTL_R_TMS")
	)
	(segment
		(start 88.427814 -223.899984)
		(end 88.4174 -223.893888)
		(width 0.0889)
		(layer "B.Cu")
		(net "JTAG_DBP_CPU1_QS_GTL_R_TMS")
	)
	(segment
		(start 102.994968 -224.7138)
		(end 102.986078 -224.70872)
		(width 0.0889)
		(layer "B.Cu")
		(net "JTAG_DBP_CPU1_QS_GTL_R_TMS")
	)
	(segment
		(start 99.235768 -224.7138)
		(end 99.226878 -224.70872)
		(width 0.0889)
		(layer "B.Cu")
		(net "JTAG_DBP_CPU1_QS_GTL_R_TMS")
	)
	(segment
		(start 99.797616 -224.373948)
		(end 99.797616 -224.389442)
		(width 0.0889)
		(layer "B.Cu")
		(net "JTAG_DBP_CPU1_QS_GTL_R_TMS")
	)
	(segment
		(start 95.859854 -224.70872)
		(end 95.850964 -224.7138)
		(width 0.0889)
		(layer "B.Cu")
		(net "JTAG_DBP_CPU1_QS_GTL_R_TMS")
	)
	(segment
		(start 90.221054 -224.70872)
		(end 90.212164 -224.7138)
		(width 0.0889)
		(layer "B.Cu")
		(net "JTAG_DBP_CPU1_QS_GTL_R_TMS")
	)
	(segment
		(start 104.874568 -227.969318)
		(end 104.865678 -227.964238)
		(width 0.0889)
		(layer "B.Cu")
		(net "JTAG_DBP_CPU1_QS_GTL_R_TMS")
	)
	(segment
		(start 102.807516 -224.389442)
		(end 102.807516 -224.379536)
		(width 0.0889)
		(layer "B.Cu")
		(net "JTAG_DBP_CPU1_QS_GTL_R_TMS")
	)
	(segment
		(start 97.918016 -224.373948)
		(end 97.918016 -224.389442)
		(width 0.0889)
		(layer "B.Cu")
		(net "JTAG_DBP_CPU1_QS_GTL_R_TMS")
	)
	(segment
		(start 97.356168 -224.7138)
		(end 97.347278 -224.70872)
		(width 0.0889)
		(layer "B.Cu")
		(net "JTAG_DBP_CPU1_QS_GTL_R_TMS")
	)
	(segment
		(start 96.886268 -223.899984)
		(end 96.875854 -223.893888)
		(width 0.0889)
		(layer "B.Cu")
		(net "JTAG_DBP_CPU1_QS_GTL_R_TMS")
	)
	(segment
		(start 89.650316 -224.389442)
		(end 89.650316 -224.379536)
		(width 0.0889)
		(layer "B.Cu")
		(net "JTAG_DBP_CPU1_QS_GTL_R_TMS")
	)
	(segment
		(start 84.154772 -223.446594)
		(end 83.71713 -223.008952)
		(width 0.12954)
		(layer "B.Cu")
		(net "JTAG_DBP_CPU1_QS_GTL_R_TMS")
	)
	(segment
		(start 83.71713 -223.008952)
		(end 83.71713 -222.115888)
		(width 0.12954)
		(layer "B.Cu")
		(net "JTAG_DBP_CPU1_QS_GTL_R_TMS")
	)
	(segment
		(start 105.344214 -228.783388)
		(end 105.335324 -228.778308)
		(width 0.0889)
		(layer "B.Cu")
		(net "JTAG_DBP_CPU1_QS_GTL_R_TMS")
	)
	(segment
		(start 98.765868 -223.899984)
		(end 98.755454 -223.893888)
		(width 0.0889)
		(layer "B.Cu")
		(net "JTAG_DBP_CPU1_QS_GTL_R_TMS")
	)
	(segment
		(start 101.115368 -224.7138)
		(end 101.106478 -224.70872)
		(width 0.0889)
		(layer "B.Cu")
		(net "JTAG_DBP_CPU1_QS_GTL_R_TMS")
	)
	(segment
		(start 91.529916 -224.389442)
		(end 91.529916 -224.379536)
		(width 0.0889)
		(layer "B.Cu")
		(net "JTAG_DBP_CPU1_QS_GTL_R_TMS")
	)
	(segment
		(start 92.100654 -224.70872)
		(end 92.091764 -224.7138)
		(width 0.0889)
		(layer "B.Cu")
		(net "JTAG_DBP_CPU1_QS_GTL_R_TMS")
	)
	(segment
		(start 106.29011 -228.786944)
		(end 106.284014 -228.783388)
		(width 0.0889)
		(layer "B.Cu")
		(net "JTAG_DBP_CPU1_QS_GTL_R_TMS")
	)
	(segment
		(start 105.156762 -228.45903)
		(end 105.156762 -228.436932)
		(width 0.0889)
		(layer "B.Cu")
		(net "JTAG_DBP_CPU1_QS_GTL_R_TMS")
	)
	(segment
		(start 104.404668 -227.155502)
		(end 104.395778 -227.150422)
		(width 0.0889)
		(layer "B.Cu")
		(net "JTAG_DBP_CPU1_QS_GTL_R_TMS")
	)
	(segment
		(start 102.525068 -223.899984)
		(end 102.514654 -223.893888)
		(width 0.0889)
		(layer "B.Cu")
		(net "JTAG_DBP_CPU1_QS_GTL_R_TMS")
	)
	(segment
		(start 110.230666 -233.34218)
		(end 110.38713 -233.613198)
		(width 0.0889)
		(layer "B.Cu")
		(net "JTAG_DBP_CPU1_QS_GTL_R_TMS")
	)
	(segment
		(start 86.021418 -200.94067)
		(end 86.021418 -196.202808)
		(width 0.12954)
		(layer "B.Cu")
		(net "JTAG_DBP_CPU1_QS_GTL_R_TMS")
	)
	(segment
		(start 83.71713 -222.115888)
		(end 81.665318 -220.064076)
		(width 0.12954)
		(layer "B.Cu")
		(net "JTAG_DBP_CPU1_QS_GTL_R_TMS")
	)
	(segment
		(start 81.665318 -209.60207)
		(end 84.459318 -206.80807)
		(width 0.12954)
		(layer "B.Cu")
		(net "JTAG_DBP_CPU1_QS_GTL_R_TMS")
	)
	(segment
		(start 89.367868 -223.899984)
		(end 89.357454 -223.893888)
		(width 0.0889)
		(layer "B.Cu")
		(net "JTAG_DBP_CPU1_QS_GTL_R_TMS")
	)
	(segment
		(start 91.247468 -223.899984)
		(end 91.237054 -223.893888)
		(width 0.0889)
		(layer "B.Cu")
		(net "JTAG_DBP_CPU1_QS_GTL_R_TMS")
	)
	(segment
		(start 101.677216 -224.373948)
		(end 101.677216 -224.389442)
		(width 0.0889)
		(layer "B.Cu")
		(net "JTAG_DBP_CPU1_QS_GTL_R_TMS")
	)
	(arc
		(start 89.828878 -224.70872)
		(mid 89.697964 -224.57236)
		(end 89.650316 -224.389442)
		(width 0.0889)
		(layer "B.Cu")
		(net "JTAG_DBP_CPU1_QS_GTL_R_TMS")
	)
	(arc
		(start 103.925878 -226.336606)
		(mid 103.794964 -226.200246)
		(end 103.747316 -226.017328)
		(width 0.0889)
		(layer "B.Cu")
		(net "JTAG_DBP_CPU1_QS_GTL_R_TMS")
	)
	(arc
		(start 107.223814 -230.41102)
		(mid 107.088881 -230.277666)
		(end 107.036616 -230.095298)
		(width 0.0889)
		(layer "B.Cu")
		(net "JTAG_DBP_CPU1_QS_GTL_R_TMS")
	)
	(arc
		(start 106.566716 -229.272846)
		(mid 106.492725 -228.99328)
		(end 106.29011 -228.786944)
		(width 0.0889)
		(layer "B.Cu")
		(net "JTAG_DBP_CPU1_QS_GTL_R_TMS")
	)
	(arc
		(start 100.927916 -224.379536)
		(mid 100.849805 -224.102587)
		(end 100.645468 -223.899984)
		(width 0.0889)
		(layer "B.Cu")
		(net "JTAG_DBP_CPU1_QS_GTL_R_TMS")
	)
	(arc
		(start 93.116654 -223.893888)
		(mid 92.838222 -223.824042)
		(end 92.56141 -223.899984)
		(width 0.0889)
		(layer "B.Cu")
		(net "JTAG_DBP_CPU1_QS_GTL_R_TMS")
	)
	(arc
		(start 85.983064 -223.899984)
		(mid 85.795866 -223.950127)
		(end 85.608668 -223.899984)
		(width 0.0889)
		(layer "B.Cu")
		(net "JTAG_DBP_CPU1_QS_GTL_R_TMS")
	)
	(arc
		(start 86.922864 -223.899984)
		(mid 86.735666 -223.950127)
		(end 86.548468 -223.899984)
		(width 0.0889)
		(layer "B.Cu")
		(net "JTAG_DBP_CPU1_QS_GTL_R_TMS")
	)
	(arc
		(start 94.996254 -223.893888)
		(mid 94.717822 -223.824042)
		(end 94.44101 -223.899984)
		(width 0.0889)
		(layer "B.Cu")
		(net "JTAG_DBP_CPU1_QS_GTL_R_TMS")
	)
	(arc
		(start 88.4174 -223.893888)
		(mid 88.139222 -223.824165)
		(end 87.862664 -223.899984)
		(width 0.0889)
		(layer "B.Cu")
		(net "JTAG_DBP_CPU1_QS_GTL_R_TMS")
	)
	(arc
		(start 101.95941 -223.899984)
		(mid 101.756587 -224.100215)
		(end 101.677216 -224.373948)
		(width 0.0889)
		(layer "B.Cu")
		(net "JTAG_DBP_CPU1_QS_GTL_R_TMS")
	)
	(arc
		(start 85.043264 -223.899984)
		(mid 84.952992 -223.937583)
		(end 84.856066 -223.95053)
		(width 0.0889)
		(layer "B.Cu")
		(net "JTAG_DBP_CPU1_QS_GTL_R_TMS")
	)
	(arc
		(start 87.862664 -223.899984)
		(mid 87.675466 -223.950127)
		(end 87.488268 -223.899984)
		(width 0.0889)
		(layer "B.Cu")
		(net "JTAG_DBP_CPU1_QS_GTL_R_TMS")
	)
	(arc
		(start 104.687116 -227.635054)
		(mid 104.609005 -227.358105)
		(end 104.404668 -227.155502)
		(width 0.0889)
		(layer "B.Cu")
		(net "JTAG_DBP_CPU1_QS_GTL_R_TMS")
	)
	(arc
		(start 96.32061 -223.899984)
		(mid 96.117787 -224.100215)
		(end 96.038416 -224.373948)
		(width 0.0889)
		(layer "B.Cu")
		(net "JTAG_DBP_CPU1_QS_GTL_R_TMS")
	)
	(arc
		(start 108.067856 -231.224836)
		(mid 107.880658 -231.274979)
		(end 107.69346 -231.224836)
		(width 0.0889)
		(layer "B.Cu")
		(net "JTAG_DBP_CPU1_QS_GTL_R_TMS")
	)
	(arc
		(start 89.650316 -224.379536)
		(mid 89.572205 -224.102587)
		(end 89.367868 -223.899984)
		(width 0.0889)
		(layer "B.Cu")
		(net "JTAG_DBP_CPU1_QS_GTL_R_TMS")
	)
	(arc
		(start 108.633768 -231.224836)
		(mid 108.350812 -231.148967)
		(end 108.067856 -231.224836)
		(width 0.0889)
		(layer "B.Cu")
		(net "JTAG_DBP_CPU1_QS_GTL_R_TMS")
	)
	(arc
		(start 97.168716 -224.379536)
		(mid 97.090605 -224.102587)
		(end 96.886268 -223.899984)
		(width 0.0889)
		(layer "B.Cu")
		(net "JTAG_DBP_CPU1_QS_GTL_R_TMS")
	)
	(arc
		(start 107.69346 -231.224836)
		(mid 107.558527 -231.091482)
		(end 107.506262 -230.909114)
		(width 0.0889)
		(layer "B.Cu")
		(net "JTAG_DBP_CPU1_QS_GTL_R_TMS")
	)
	(arc
		(start 109.856016 -233.34218)
		(mid 109.7821 -233.062678)
		(end 109.579664 -232.856278)
		(width 0.0889)
		(layer "B.Cu")
		(net "JTAG_DBP_CPU1_QS_GTL_R_TMS")
	)
	(arc
		(start 97.918016 -224.389442)
		(mid 97.870337 -224.572342)
		(end 97.739454 -224.70872)
		(width 0.0889)
		(layer "B.Cu")
		(net "JTAG_DBP_CPU1_QS_GTL_R_TMS")
	)
	(arc
		(start 91.529916 -224.379536)
		(mid 91.451805 -224.102587)
		(end 91.247468 -223.899984)
		(width 0.0889)
		(layer "B.Cu")
		(net "JTAG_DBP_CPU1_QS_GTL_R_TMS")
	)
	(arc
		(start 90.68181 -223.899984)
		(mid 90.478987 -224.100215)
		(end 90.399616 -224.373948)
		(width 0.0889)
		(layer "B.Cu")
		(net "JTAG_DBP_CPU1_QS_GTL_R_TMS")
	)
	(arc
		(start 99.226878 -224.70872)
		(mid 99.095964 -224.57236)
		(end 99.048316 -224.389442)
		(width 0.0889)
		(layer "B.Cu")
		(net "JTAG_DBP_CPU1_QS_GTL_R_TMS")
	)
	(arc
		(start 102.807516 -224.379536)
		(mid 102.729405 -224.102587)
		(end 102.525068 -223.899984)
		(width 0.0889)
		(layer "B.Cu")
		(net "JTAG_DBP_CPU1_QS_GTL_R_TMS")
	)
	(arc
		(start 104.217216 -226.821238)
		(mid 104.139105 -226.544289)
		(end 103.934768 -226.341686)
		(width 0.0889)
		(layer "B.Cu")
		(net "JTAG_DBP_CPU1_QS_GTL_R_TMS")
	)
	(arc
		(start 99.797616 -224.389442)
		(mid 99.749937 -224.572342)
		(end 99.619054 -224.70872)
		(width 0.0889)
		(layer "B.Cu")
		(net "JTAG_DBP_CPU1_QS_GTL_R_TMS")
	)
	(arc
		(start 101.677216 -224.389442)
		(mid 101.629537 -224.572342)
		(end 101.498654 -224.70872)
		(width 0.0889)
		(layer "B.Cu")
		(net "JTAG_DBP_CPU1_QS_GTL_R_TMS")
	)
	(arc
		(start 106.269282 -228.774752)
		(mid 105.992807 -228.707432)
		(end 105.71861 -228.783388)
		(width 0.0889)
		(layer "B.Cu")
		(net "JTAG_DBP_CPU1_QS_GTL_R_TMS")
	)
	(arc
		(start 102.514654 -223.893888)
		(mid 102.236222 -223.824042)
		(end 101.95941 -223.899984)
		(width 0.0889)
		(layer "B.Cu")
		(net "JTAG_DBP_CPU1_QS_GTL_R_TMS")
	)
	(arc
		(start 109.386116 -232.528364)
		(mid 109.312125 -232.248798)
		(end 109.10951 -232.042462)
		(width 0.0889)
		(layer "B.Cu")
		(net "JTAG_DBP_CPU1_QS_GTL_R_TMS")
	)
	(arc
		(start 100.07981 -223.899984)
		(mid 99.876987 -224.100215)
		(end 99.797616 -224.373948)
		(width 0.0889)
		(layer "B.Cu")
		(net "JTAG_DBP_CPU1_QS_GTL_R_TMS")
	)
	(arc
		(start 103.747316 -226.003104)
		(mid 103.668097 -225.728419)
		(end 103.464614 -225.527616)
		(width 0.0889)
		(layer "B.Cu")
		(net "JTAG_DBP_CPU1_QS_GTL_R_TMS")
	)
	(arc
		(start 104.395778 -227.150422)
		(mid 104.264864 -227.014062)
		(end 104.217216 -226.831144)
		(width 0.0889)
		(layer "B.Cu")
		(net "JTAG_DBP_CPU1_QS_GTL_R_TMS")
	)
	(arc
		(start 85.608668 -223.899984)
		(mid 85.334469 -223.824149)
		(end 85.057996 -223.891348)
		(width 0.0889)
		(layer "B.Cu")
		(net "JTAG_DBP_CPU1_QS_GTL_R_TMS")
	)
	(arc
		(start 93.409516 -224.379536)
		(mid 93.331405 -224.102587)
		(end 93.127068 -223.899984)
		(width 0.0889)
		(layer "B.Cu")
		(net "JTAG_DBP_CPU1_QS_GTL_R_TMS")
	)
	(arc
		(start 97.730564 -224.7138)
		(mid 97.543366 -224.763943)
		(end 97.356168 -224.7138)
		(width 0.0889)
		(layer "B.Cu")
		(net "JTAG_DBP_CPU1_QS_GTL_R_TMS")
	)
	(arc
		(start 107.036616 -230.076756)
		(mid 106.958505 -229.799807)
		(end 106.754168 -229.597204)
		(width 0.0889)
		(layer "B.Cu")
		(net "JTAG_DBP_CPU1_QS_GTL_R_TMS")
	)
	(arc
		(start 86.548468 -223.899984)
		(mid 86.265766 -223.824208)
		(end 85.983064 -223.899984)
		(width 0.0889)
		(layer "B.Cu")
		(net "JTAG_DBP_CPU1_QS_GTL_R_TMS")
	)
	(arc
		(start 88.80221 -223.899984)
		(mid 88.615012 -223.950127)
		(end 88.427814 -223.899984)
		(width 0.0889)
		(layer "B.Cu")
		(net "JTAG_DBP_CPU1_QS_GTL_R_TMS")
	)
	(arc
		(start 95.850964 -224.7138)
		(mid 95.663766 -224.763943)
		(end 95.476568 -224.7138)
		(width 0.0889)
		(layer "B.Cu")
		(net "JTAG_DBP_CPU1_QS_GTL_R_TMS")
	)
	(arc
		(start 101.106478 -224.70872)
		(mid 100.975564 -224.57236)
		(end 100.927916 -224.389442)
		(width 0.0889)
		(layer "B.Cu")
		(net "JTAG_DBP_CPU1_QS_GTL_R_TMS")
	)
	(arc
		(start 100.635054 -223.893888)
		(mid 100.356622 -223.824042)
		(end 100.07981 -223.899984)
		(width 0.0889)
		(layer "B.Cu")
		(net "JTAG_DBP_CPU1_QS_GTL_R_TMS")
	)
	(arc
		(start 105.335324 -228.778308)
		(mid 105.20441 -228.641948)
		(end 105.156762 -228.45903)
		(width 0.0889)
		(layer "B.Cu")
		(net "JTAG_DBP_CPU1_QS_GTL_R_TMS")
	)
	(arc
		(start 103.277162 -225.187764)
		(mid 103.197792 -224.91403)
		(end 102.994968 -224.7138)
		(width 0.0889)
		(layer "B.Cu")
		(net "JTAG_DBP_CPU1_QS_GTL_R_TMS")
	)
	(arc
		(start 89.357454 -223.893888)
		(mid 89.079022 -223.824042)
		(end 88.80221 -223.899984)
		(width 0.0889)
		(layer "B.Cu")
		(net "JTAG_DBP_CPU1_QS_GTL_R_TMS")
	)
	(arc
		(start 93.588078 -224.70872)
		(mid 93.457164 -224.57236)
		(end 93.409516 -224.389442)
		(width 0.0889)
		(layer "B.Cu")
		(net "JTAG_DBP_CPU1_QS_GTL_R_TMS")
	)
	(arc
		(start 92.56141 -223.899984)
		(mid 92.358587 -224.100215)
		(end 92.279216 -224.373948)
		(width 0.0889)
		(layer "B.Cu")
		(net "JTAG_DBP_CPU1_QS_GTL_R_TMS")
	)
	(arc
		(start 105.71861 -228.783388)
		(mid 105.531412 -228.833531)
		(end 105.344214 -228.783388)
		(width 0.0889)
		(layer "B.Cu")
		(net "JTAG_DBP_CPU1_QS_GTL_R_TMS")
	)
	(arc
		(start 99.048316 -224.379536)
		(mid 98.970205 -224.102587)
		(end 98.765868 -223.899984)
		(width 0.0889)
		(layer "B.Cu")
		(net "JTAG_DBP_CPU1_QS_GTL_R_TMS")
	)
	(arc
		(start 106.745278 -229.592124)
		(mid 106.614364 -229.455764)
		(end 106.566716 -229.272846)
		(width 0.0889)
		(layer "B.Cu")
		(net "JTAG_DBP_CPU1_QS_GTL_R_TMS")
	)
	(arc
		(start 101.489764 -224.7138)
		(mid 101.302566 -224.763943)
		(end 101.115368 -224.7138)
		(width 0.0889)
		(layer "B.Cu")
		(net "JTAG_DBP_CPU1_QS_GTL_R_TMS")
	)
	(arc
		(start 102.986078 -224.70872)
		(mid 102.855164 -224.57236)
		(end 102.807516 -224.389442)
		(width 0.0889)
		(layer "B.Cu")
		(net "JTAG_DBP_CPU1_QS_GTL_R_TMS")
	)
	(arc
		(start 109.564678 -232.847642)
		(mid 109.433764 -232.711282)
		(end 109.386116 -232.528364)
		(width 0.0889)
		(layer "B.Cu")
		(net "JTAG_DBP_CPU1_QS_GTL_R_TMS")
	)
	(arc
		(start 98.755454 -223.893888)
		(mid 98.477022 -223.824042)
		(end 98.20021 -223.899984)
		(width 0.0889)
		(layer "B.Cu")
		(net "JTAG_DBP_CPU1_QS_GTL_R_TMS")
	)
	(arc
		(start 110.034578 -233.661458)
		(mid 109.903664 -233.525098)
		(end 109.856016 -233.34218)
		(width 0.0889)
		(layer "B.Cu")
		(net "JTAG_DBP_CPU1_QS_GTL_R_TMS")
	)
	(arc
		(start 94.158816 -224.389442)
		(mid 94.111137 -224.572342)
		(end 93.980254 -224.70872)
		(width 0.0889)
		(layer "B.Cu")
		(net "JTAG_DBP_CPU1_QS_GTL_R_TMS")
	)
	(arc
		(start 90.399616 -224.389442)
		(mid 90.351937 -224.572342)
		(end 90.221054 -224.70872)
		(width 0.0889)
		(layer "B.Cu")
		(net "JTAG_DBP_CPU1_QS_GTL_R_TMS")
	)
	(arc
		(start 87.488268 -223.899984)
		(mid 87.205566 -223.824208)
		(end 86.922864 -223.899984)
		(width 0.0889)
		(layer "B.Cu")
		(net "JTAG_DBP_CPU1_QS_GTL_R_TMS")
	)
	(arc
		(start 99.610164 -224.7138)
		(mid 99.422966 -224.763943)
		(end 99.235768 -224.7138)
		(width 0.0889)
		(layer "B.Cu")
		(net "JTAG_DBP_CPU1_QS_GTL_R_TMS")
	)
	(arc
		(start 110.366048 -233.691176)
		(mid 110.201952 -233.715523)
		(end 110.043468 -233.666538)
		(width 0.0889)
		(layer "B.Cu")
		(net "JTAG_DBP_CPU1_QS_GTL_R_TMS")
	)
	(arc
		(start 95.467678 -224.70872)
		(mid 95.336764 -224.57236)
		(end 95.289116 -224.389442)
		(width 0.0889)
		(layer "B.Cu")
		(net "JTAG_DBP_CPU1_QS_GTL_R_TMS")
	)
	(arc
		(start 109.094524 -232.033826)
		(mid 108.96361 -231.897466)
		(end 108.915962 -231.714548)
		(width 0.0889)
		(layer "B.Cu")
		(net "JTAG_DBP_CPU1_QS_GTL_R_TMS")
	)
	(arc
		(start 93.971364 -224.7138)
		(mid 93.784166 -224.763943)
		(end 93.596968 -224.7138)
		(width 0.0889)
		(layer "B.Cu")
		(net "JTAG_DBP_CPU1_QS_GTL_R_TMS")
	)
	(arc
		(start 96.038416 -224.389442)
		(mid 95.990737 -224.572342)
		(end 95.859854 -224.70872)
		(width 0.0889)
		(layer "B.Cu")
		(net "JTAG_DBP_CPU1_QS_GTL_R_TMS")
	)
	(arc
		(start 107.506262 -230.884984)
		(mid 107.426813 -230.611188)
		(end 107.223814 -230.41102)
		(width 0.0889)
		(layer "B.Cu")
		(net "JTAG_DBP_CPU1_QS_GTL_R_TMS")
	)
	(arc
		(start 98.20021 -223.899984)
		(mid 97.997387 -224.100215)
		(end 97.918016 -224.373948)
		(width 0.0889)
		(layer "B.Cu")
		(net "JTAG_DBP_CPU1_QS_GTL_R_TMS")
	)
	(arc
		(start 94.44101 -223.899984)
		(mid 94.238187 -224.100215)
		(end 94.158816 -224.373948)
		(width 0.0889)
		(layer "B.Cu")
		(net "JTAG_DBP_CPU1_QS_GTL_R_TMS")
	)
	(arc
		(start 97.347278 -224.70872)
		(mid 97.216364 -224.57236)
		(end 97.168716 -224.389442)
		(width 0.0889)
		(layer "B.Cu")
		(net "JTAG_DBP_CPU1_QS_GTL_R_TMS")
	)
	(arc
		(start 92.279216 -224.389442)
		(mid 92.231537 -224.572342)
		(end 92.100654 -224.70872)
		(width 0.0889)
		(layer "B.Cu")
		(net "JTAG_DBP_CPU1_QS_GTL_R_TMS")
	)
	(arc
		(start 91.237054 -223.893888)
		(mid 90.958622 -223.824042)
		(end 90.68181 -223.899984)
		(width 0.0889)
		(layer "B.Cu")
		(net "JTAG_DBP_CPU1_QS_GTL_R_TMS")
	)
	(arc
		(start 96.875854 -223.893888)
		(mid 96.597422 -223.824042)
		(end 96.32061 -223.899984)
		(width 0.0889)
		(layer "B.Cu")
		(net "JTAG_DBP_CPU1_QS_GTL_R_TMS")
	)
	(arc
		(start 90.212164 -224.7138)
		(mid 90.024966 -224.763943)
		(end 89.837768 -224.7138)
		(width 0.0889)
		(layer "B.Cu")
		(net "JTAG_DBP_CPU1_QS_GTL_R_TMS")
	)
	(arc
		(start 95.289116 -224.379536)
		(mid 95.211005 -224.102587)
		(end 95.006668 -223.899984)
		(width 0.0889)
		(layer "B.Cu")
		(net "JTAG_DBP_CPU1_QS_GTL_R_TMS")
	)
	(arc
		(start 105.156762 -228.436932)
		(mid 105.075851 -228.166804)
		(end 104.874568 -227.969318)
		(width 0.0889)
		(layer "B.Cu")
		(net "JTAG_DBP_CPU1_QS_GTL_R_TMS")
	)
	(arc
		(start 108.915962 -231.69245)
		(mid 108.835051 -231.422322)
		(end 108.633768 -231.224836)
		(width 0.0889)
		(layer "B.Cu")
		(net "JTAG_DBP_CPU1_QS_GTL_R_TMS")
	)
	(arc
		(start 92.091764 -224.7138)
		(mid 91.904566 -224.763943)
		(end 91.717368 -224.7138)
		(width 0.0889)
		(layer "B.Cu")
		(net "JTAG_DBP_CPU1_QS_GTL_R_TMS")
	)
	(arc
		(start 104.865678 -227.964238)
		(mid 104.734764 -227.827878)
		(end 104.687116 -227.64496)
		(width 0.0889)
		(layer "B.Cu")
		(net "JTAG_DBP_CPU1_QS_GTL_R_TMS")
	)
	(arc
		(start 91.708478 -224.70872)
		(mid 91.577564 -224.57236)
		(end 91.529916 -224.389442)
		(width 0.0889)
		(layer "B.Cu")
		(net "JTAG_DBP_CPU1_QS_GTL_R_TMS")
	)
	(arc
		(start 103.455724 -225.522536)
		(mid 103.32481 -225.386176)
		(end 103.277162 -225.203258)
		(width 0.0889)
		(layer "B.Cu")
		(net "JTAG_DBP_CPU1_QS_GTL_R_TMS")
	)
	(segment
		(start 111.640112 -232.528618)
		(end 111.640366 -232.528364)
		(width 0.12954)
		(layer "F.Cu")
		(net "JTAG_DBP_CPU1_GTL_R_TDI")
	)
	(segment
		(start 111.640112 -233.064304)
		(end 111.640112 -232.528618)
		(width 0.12954)
		(layer "F.Cu")
		(net "JTAG_DBP_CPU1_GTL_R_TDI")
	)
	(via
		(at 111.640366 -232.528364)
		(size 0.4572)
		(drill 0.2032)
		(layers "F.Cu" "B.Cu")
		(net "JTAG_DBP_CPU1_GTL_R_TDI")
	)
	(via
		(at 94.517718 -197.758304)
		(size 0.7112)
		(drill 0.3556)
		(layers "F.Cu" "B.Cu")
		(net "JTAG_DBP_CPU1_GTL_R_TDI")
	)
	(segment
		(start 88.943688 -213.122256)
		(end 90.272108 -211.793836)
		(width 0.12954)
		(layer "B.Cu")
		(net "JTAG_DBP_CPU1_GTL_R_TDI")
	)
	(segment
		(start 112.862614 -233.017822)
		(end 112.862614 -233.017568)
		(width 0.0889)
		(layer "B.Cu")
		(net "JTAG_DBP_CPU1_GTL_R_TDI")
	)
	(segment
		(start 109.855762 -225.203258)
		(end 109.855762 -225.187764)
		(width 0.0889)
		(layer "B.Cu")
		(net "JTAG_DBP_CPU1_GTL_R_TDI")
	)
	(segment
		(start 110.325916 -226.017328)
		(end 110.325916 -226.003104)
		(width 0.0889)
		(layer "B.Cu")
		(net "JTAG_DBP_CPU1_GTL_R_TDI")
	)
	(segment
		(start 111.949484 -232.761028)
		(end 112.076484 -232.856786)
		(width 0.0889)
		(layer "B.Cu")
		(net "JTAG_DBP_CPU1_GTL_R_TDI")
	)
	(segment
		(start 112.675416 -230.086662)
		(end 112.675416 -230.076756)
		(width 0.0889)
		(layer "B.Cu")
		(net "JTAG_DBP_CPU1_GTL_R_TDI")
	)
	(segment
		(start 94.066614 -219.01658)
		(end 94.051882 -219.007944)
		(width 0.0889)
		(layer "B.Cu")
		(net "JTAG_DBP_CPU1_GTL_R_TDI")
	)
	(segment
		(start 90.272108 -211.793836)
		(end 91.544648 -211.793836)
		(width 0.12954)
		(layer "B.Cu")
		(net "JTAG_DBP_CPU1_GTL_R_TDI")
	)
	(segment
		(start 93.126814 -219.01658)
		(end 93.112082 -219.007944)
		(width 0.0889)
		(layer "B.Cu")
		(net "JTAG_DBP_CPU1_GTL_R_TDI")
	)
	(segment
		(start 111.735616 -228.467666)
		(end 111.735616 -228.440488)
		(width 0.0889)
		(layer "B.Cu")
		(net "JTAG_DBP_CPU1_GTL_R_TDI")
	)
	(segment
		(start 89.180416 -218.700858)
		(end 89.180416 -218.682316)
		(width 0.0889)
		(layer "B.Cu")
		(net "JTAG_DBP_CPU1_GTL_R_TDI")
	)
	(segment
		(start 113.145316 -230.922576)
		(end 113.145316 -230.884984)
		(width 0.0889)
		(layer "B.Cu")
		(net "JTAG_DBP_CPU1_GTL_R_TDI")
	)
	(segment
		(start 88.710516 -217.878406)
		(end 88.710516 -217.864182)
		(width 0.0889)
		(layer "B.Cu")
		(net "JTAG_DBP_CPU1_GTL_R_TDI")
	)
	(segment
		(start 104.41051 -219.020136)
		(end 104.404414 -219.01658)
		(width 0.0889)
		(layer "B.Cu")
		(net "JTAG_DBP_CPU1_GTL_R_TDI")
	)
	(segment
		(start 87.488014 -215.761062)
		(end 87.479124 -215.755982)
		(width 0.0889)
		(layer "B.Cu")
		(net "JTAG_DBP_CPU1_GTL_R_TDI")
	)
	(segment
		(start 110.98911 -227.159058)
		(end 110.983014 -227.155502)
		(width 0.0889)
		(layer "B.Cu")
		(net "JTAG_DBP_CPU1_GTL_R_TDI")
	)
	(segment
		(start 104.874568 -219.830396)
		(end 104.865678 -219.825316)
		(width 0.0889)
		(layer "B.Cu")
		(net "JTAG_DBP_CPU1_GTL_R_TDI")
	)
	(segment
		(start 87.770208 -216.25052)
		(end 87.770208 -216.235026)
		(width 0.0889)
		(layer "B.Cu")
		(net "JTAG_DBP_CPU1_GTL_R_TDI")
	)
	(segment
		(start 110.795816 -226.83978)
		(end 110.795816 -226.821238)
		(width 0.0889)
		(layer "B.Cu")
		(net "JTAG_DBP_CPU1_GTL_R_TDI")
	)
	(segment
		(start 103.464614 -219.01658)
		(end 103.449882 -219.007944)
		(width 0.0889)
		(layer "B.Cu")
		(net "JTAG_DBP_CPU1_GTL_R_TDI")
	)
	(segment
		(start 111.640366 -232.528364)
		(end 111.822484 -232.665524)
		(width 0.0889)
		(layer "B.Cu")
		(net "JTAG_DBP_CPU1_GTL_R_TDI")
	)
	(segment
		(start 112.863122 -230.41102)
		(end 112.854232 -230.40594)
		(width 0.0889)
		(layer "B.Cu")
		(net "JTAG_DBP_CPU1_GTL_R_TDI")
	)
	(segment
		(start 107.506516 -221.133924)
		(end 107.506516 -221.1197)
		(width 0.0889)
		(layer "B.Cu")
		(net "JTAG_DBP_CPU1_GTL_R_TDI")
	)
	(segment
		(start 91.544648 -211.793836)
		(end 94.517718 -208.820766)
		(width 0.12954)
		(layer "B.Cu")
		(net "JTAG_DBP_CPU1_GTL_R_TDI")
	)
	(segment
		(start 88.897968 -218.202764)
		(end 88.889078 -218.197684)
		(width 0.0889)
		(layer "B.Cu")
		(net "JTAG_DBP_CPU1_GTL_R_TDI")
	)
	(segment
		(start 109.573568 -224.7138)
		(end 109.564678 -224.70872)
		(width 0.0889)
		(layer "B.Cu")
		(net "JTAG_DBP_CPU1_GTL_R_TDI")
	)
	(segment
		(start 112.268762 -233.001566)
		(end 112.297464 -233.017822)
		(width 0.0889)
		(layer "B.Cu")
		(net "JTAG_DBP_CPU1_GTL_R_TDI")
	)
	(segment
		(start 87.691722 -214.582756)
		(end 87.691722 -214.370412)
		(width 0.12954)
		(layer "B.Cu")
		(net "JTAG_DBP_CPU1_GTL_R_TDI")
	)
	(segment
		(start 102.524814 -219.01658)
		(end 102.510082 -219.007944)
		(width 0.0889)
		(layer "B.Cu")
		(net "JTAG_DBP_CPU1_GTL_R_TDI")
	)
	(segment
		(start 113.145316 -232.528364)
		(end 113.145316 -232.527856)
		(width 0.0889)
		(layer "B.Cu")
		(net "JTAG_DBP_CPU1_GTL_R_TDI")
	)
	(segment
		(start 112.076484 -232.856786)
		(end 112.268762 -233.001566)
		(width 0.0889)
		(layer "B.Cu")
		(net "JTAG_DBP_CPU1_GTL_R_TDI")
	)
	(segment
		(start 92.187014 -219.01658)
		(end 92.172282 -219.007944)
		(width 0.0889)
		(layer "B.Cu")
		(net "JTAG_DBP_CPU1_GTL_R_TDI")
	)
	(segment
		(start 109.103414 -222.272098)
		(end 109.088682 -222.263462)
		(width 0.0889)
		(layer "B.Cu")
		(net "JTAG_DBP_CPU1_GTL_R_TDI")
	)
	(segment
		(start 107.693968 -221.458282)
		(end 107.685078 -221.453202)
		(width 0.0889)
		(layer "B.Cu")
		(net "JTAG_DBP_CPU1_GTL_R_TDI")
	)
	(segment
		(start 112.86236 -233.017822)
		(end 112.862614 -233.017822)
		(width 0.0889)
		(layer "B.Cu")
		(net "JTAG_DBP_CPU1_GTL_R_TDI")
	)
	(segment
		(start 94.517718 -208.820766)
		(end 94.517718 -197.758304)
		(width 0.12954)
		(layer "B.Cu")
		(net "JTAG_DBP_CPU1_GTL_R_TDI")
	)
	(segment
		(start 105.263696 -219.82176)
		(end 105.248964 -219.830396)
		(width 0.0889)
		(layer "B.Cu")
		(net "JTAG_DBP_CPU1_GTL_R_TDI")
	)
	(segment
		(start 87.963756 -216.578434)
		(end 87.95766 -216.574878)
		(width 0.0889)
		(layer "B.Cu")
		(net "JTAG_DBP_CPU1_GTL_R_TDI")
	)
	(segment
		(start 109.10951 -222.275654)
		(end 109.103414 -222.272098)
		(width 0.0889)
		(layer "B.Cu")
		(net "JTAG_DBP_CPU1_GTL_R_TDI")
	)
	(segment
		(start 110.513368 -226.341686)
		(end 110.504478 -226.336606)
		(width 0.0889)
		(layer "B.Cu")
		(net "JTAG_DBP_CPU1_GTL_R_TDI")
	)
	(segment
		(start 96.886014 -219.01658)
		(end 96.871282 -219.007944)
		(width 0.0889)
		(layer "B.Cu")
		(net "JTAG_DBP_CPU1_GTL_R_TDI")
	)
	(segment
		(start 112.854232 -231.39527)
		(end 112.863122 -231.39019)
		(width 0.0889)
		(layer "B.Cu")
		(net "JTAG_DBP_CPU1_GTL_R_TDI")
	)
	(segment
		(start 87.95766 -216.574878)
		(end 87.94877 -216.569798)
		(width 0.0889)
		(layer "B.Cu")
		(net "JTAG_DBP_CPU1_GTL_R_TDI")
	)
	(segment
		(start 107.976162 -221.94774)
		(end 107.976162 -221.932246)
		(width 0.0889)
		(layer "B.Cu")
		(net "JTAG_DBP_CPU1_GTL_R_TDI")
	)
	(segment
		(start 109.573568 -224.065084)
		(end 109.579664 -224.061528)
		(width 0.0889)
		(layer "B.Cu")
		(net "JTAG_DBP_CPU1_GTL_R_TDI")
	)
	(segment
		(start 112.67567 -230.086662)
		(end 112.675416 -230.086662)
		(width 0.0889)
		(layer "B.Cu")
		(net "JTAG_DBP_CPU1_GTL_R_TDI")
	)
	(segment
		(start 95.006414 -219.01658)
		(end 94.991682 -219.007944)
		(width 0.0889)
		(layer "B.Cu")
		(net "JTAG_DBP_CPU1_GTL_R_TDI")
	)
	(segment
		(start 100.645214 -219.01658)
		(end 100.630482 -219.007944)
		(width 0.0889)
		(layer "B.Cu")
		(net "JTAG_DBP_CPU1_GTL_R_TDI")
	)
	(segment
		(start 87.691722 -214.370412)
		(end 88.939878 -213.122256)
		(width 0.12954)
		(layer "B.Cu")
		(net "JTAG_DBP_CPU1_GTL_R_TDI")
	)
	(segment
		(start 112.392968 -229.597204)
		(end 112.384078 -229.592124)
		(width 0.0889)
		(layer "B.Cu")
		(net "JTAG_DBP_CPU1_GTL_R_TDI")
	)
	(segment
		(start 109.564678 -224.070164)
		(end 109.573568 -224.065084)
		(width 0.0889)
		(layer "B.Cu")
		(net "JTAG_DBP_CPU1_GTL_R_TDI")
	)
	(segment
		(start 99.705414 -219.01658)
		(end 99.690682 -219.007944)
		(width 0.0889)
		(layer "B.Cu")
		(net "JTAG_DBP_CPU1_GTL_R_TDI")
	)
	(segment
		(start 88.939878 -213.122256)
		(end 88.943688 -213.122256)
		(width 0.12954)
		(layer "B.Cu")
		(net "JTAG_DBP_CPU1_GTL_R_TDI")
	)
	(segment
		(start 111.453168 -227.969318)
		(end 111.444278 -227.964238)
		(width 0.0889)
		(layer "B.Cu")
		(net "JTAG_DBP_CPU1_GTL_R_TDI")
	)
	(segment
		(start 111.822484 -232.665524)
		(end 111.949484 -232.761028)
		(width 0.0889)
		(layer "B.Cu")
		(net "JTAG_DBP_CPU1_GTL_R_TDI")
	)
	(segment
		(start 88.427814 -217.388694)
		(end 88.418924 -217.383614)
		(width 0.0889)
		(layer "B.Cu")
		(net "JTAG_DBP_CPU1_GTL_R_TDI")
	)
	(segment
		(start 87.300562 -215.436704)
		(end 87.300562 -214.973916)
		(width 0.0889)
		(layer "B.Cu")
		(net "JTAG_DBP_CPU1_GTL_R_TDI")
	)
	(segment
		(start 95.946214 -219.01658)
		(end 95.931482 -219.007944)
		(width 0.0889)
		(layer "B.Cu")
		(net "JTAG_DBP_CPU1_GTL_R_TDI")
	)
	(segment
		(start 91.247214 -219.01658)
		(end 91.232482 -219.007944)
		(width 0.0889)
		(layer "B.Cu")
		(net "JTAG_DBP_CPU1_GTL_R_TDI")
	)
	(segment
		(start 97.825814 -219.01658)
		(end 97.811082 -219.007944)
		(width 0.0889)
		(layer "B.Cu")
		(net "JTAG_DBP_CPU1_GTL_R_TDI")
	)
	(segment
		(start 90.307414 -219.01658)
		(end 90.292682 -219.007944)
		(width 0.0889)
		(layer "B.Cu")
		(net "JTAG_DBP_CPU1_GTL_R_TDI")
	)
	(segment
		(start 112.863122 -232.038906)
		(end 112.854232 -232.033826)
		(width 0.0889)
		(layer "B.Cu")
		(net "JTAG_DBP_CPU1_GTL_R_TDI")
	)
	(segment
		(start 110.043214 -225.527616)
		(end 110.034324 -225.522536)
		(width 0.0889)
		(layer "B.Cu")
		(net "JTAG_DBP_CPU1_GTL_R_TDI")
	)
	(segment
		(start 97.257108 -193.5861)
		(end 97.257108 -191.105282)
		(width 0.12954)
		(layer "B.Cu")
		(net "JTAG_DBP_CPU1_GTL_R_TDI")
	)
	(segment
		(start 107.036616 -220.32849)
		(end 107.036616 -220.309948)
		(width 0.0889)
		(layer "B.Cu")
		(net "JTAG_DBP_CPU1_GTL_R_TDI")
	)
	(segment
		(start 87.300562 -214.973916)
		(end 87.691722 -214.582756)
		(width 0.12954)
		(layer "B.Cu")
		(net "JTAG_DBP_CPU1_GTL_R_TDI")
	)
	(segment
		(start 109.573568 -223.085914)
		(end 109.564678 -223.080834)
		(width 0.0889)
		(layer "B.Cu")
		(net "JTAG_DBP_CPU1_GTL_R_TDI")
	)
	(segment
		(start 109.856016 -223.575626)
		(end 109.856016 -223.561402)
		(width 0.0889)
		(layer "B.Cu")
		(net "JTAG_DBP_CPU1_GTL_R_TDI")
	)
	(segment
		(start 98.765614 -219.01658)
		(end 98.750882 -219.007944)
		(width 0.0889)
		(layer "B.Cu")
		(net "JTAG_DBP_CPU1_GTL_R_TDI")
	)
	(segment
		(start 104.404414 -219.01658)
		(end 104.389682 -219.007944)
		(width 0.0889)
		(layer "B.Cu")
		(net "JTAG_DBP_CPU1_GTL_R_TDI")
	)
	(segment
		(start 94.517718 -197.758304)
		(end 94.517718 -196.32549)
		(width 0.12954)
		(layer "B.Cu")
		(net "JTAG_DBP_CPU1_GTL_R_TDI")
	)
	(segment
		(start 111.935006 -228.7905)
		(end 111.922814 -228.783388)
		(width 0.0889)
		(layer "B.Cu")
		(net "JTAG_DBP_CPU1_GTL_R_TDI")
	)
	(segment
		(start 108.163614 -222.272098)
		(end 108.154724 -222.267018)
		(width 0.0889)
		(layer "B.Cu")
		(net "JTAG_DBP_CPU1_GTL_R_TDI")
	)
	(segment
		(start 101.585014 -219.01658)
		(end 101.570282 -219.007944)
		(width 0.0889)
		(layer "B.Cu")
		(net "JTAG_DBP_CPU1_GTL_R_TDI")
	)
	(segment
		(start 94.517718 -196.32549)
		(end 97.257108 -193.5861)
		(width 0.12954)
		(layer "B.Cu")
		(net "JTAG_DBP_CPU1_GTL_R_TDI")
	)
	(arc
		(start 113.145316 -232.527856)
		(mid 113.069701 -232.245592)
		(end 112.863122 -232.038906)
		(width 0.0889)
		(layer "B.Cu")
		(net "JTAG_DBP_CPU1_GTL_R_TDI")
	)
	(arc
		(start 89.367614 -219.01658)
		(mid 89.232681 -218.883226)
		(end 89.180416 -218.700858)
		(width 0.0889)
		(layer "B.Cu")
		(net "JTAG_DBP_CPU1_GTL_R_TDI")
	)
	(arc
		(start 110.983014 -227.155502)
		(mid 110.848081 -227.022148)
		(end 110.795816 -226.83978)
		(width 0.0889)
		(layer "B.Cu")
		(net "JTAG_DBP_CPU1_GTL_R_TDI")
	)
	(arc
		(start 87.94877 -216.569798)
		(mid 87.817856 -216.433438)
		(end 87.770208 -216.25052)
		(width 0.0889)
		(layer "B.Cu")
		(net "JTAG_DBP_CPU1_GTL_R_TDI")
	)
	(arc
		(start 88.418924 -217.383614)
		(mid 88.28801 -217.247254)
		(end 88.240362 -217.064336)
		(width 0.0889)
		(layer "B.Cu")
		(net "JTAG_DBP_CPU1_GTL_R_TDI")
	)
	(arc
		(start 103.83901 -219.01658)
		(mid 103.651812 -219.066723)
		(end 103.464614 -219.01658)
		(width 0.0889)
		(layer "B.Cu")
		(net "JTAG_DBP_CPU1_GTL_R_TDI")
	)
	(arc
		(start 95.38081 -219.01658)
		(mid 95.193612 -219.066723)
		(end 95.006414 -219.01658)
		(width 0.0889)
		(layer "B.Cu")
		(net "JTAG_DBP_CPU1_GTL_R_TDI")
	)
	(arc
		(start 107.223814 -220.644212)
		(mid 107.088881 -220.510858)
		(end 107.036616 -220.32849)
		(width 0.0889)
		(layer "B.Cu")
		(net "JTAG_DBP_CPU1_GTL_R_TDI")
	)
	(arc
		(start 96.32061 -219.01658)
		(mid 96.133412 -219.066723)
		(end 95.946214 -219.01658)
		(width 0.0889)
		(layer "B.Cu")
		(net "JTAG_DBP_CPU1_GTL_R_TDI")
	)
	(arc
		(start 108.53801 -222.272098)
		(mid 108.350812 -222.322241)
		(end 108.163614 -222.272098)
		(width 0.0889)
		(layer "B.Cu")
		(net "JTAG_DBP_CPU1_GTL_R_TDI")
	)
	(arc
		(start 112.854232 -232.033826)
		(mid 112.675635 -231.714548)
		(end 112.854232 -231.39527)
		(width 0.0889)
		(layer "B.Cu")
		(net "JTAG_DBP_CPU1_GTL_R_TDI")
	)
	(arc
		(start 101.95941 -219.01658)
		(mid 101.772212 -219.066723)
		(end 101.585014 -219.01658)
		(width 0.0889)
		(layer "B.Cu")
		(net "JTAG_DBP_CPU1_GTL_R_TDI")
	)
	(arc
		(start 106.188764 -219.830396)
		(mid 106.001566 -219.880539)
		(end 105.814368 -219.830396)
		(width 0.0889)
		(layer "B.Cu")
		(net "JTAG_DBP_CPU1_GTL_R_TDI")
	)
	(arc
		(start 112.863122 -231.39019)
		(mid 113.064404 -231.192703)
		(end 113.145316 -230.922576)
		(width 0.0889)
		(layer "B.Cu")
		(net "JTAG_DBP_CPU1_GTL_R_TDI")
	)
	(arc
		(start 107.685078 -221.453202)
		(mid 107.554164 -221.316842)
		(end 107.506516 -221.133924)
		(width 0.0889)
		(layer "B.Cu")
		(net "JTAG_DBP_CPU1_GTL_R_TDI")
	)
	(arc
		(start 100.630482 -219.007944)
		(mid 100.354007 -218.940624)
		(end 100.07981 -219.01658)
		(width 0.0889)
		(layer "B.Cu")
		(net "JTAG_DBP_CPU1_GTL_R_TDI")
	)
	(arc
		(start 99.690682 -219.007944)
		(mid 99.414207 -218.940624)
		(end 99.14001 -219.01658)
		(width 0.0889)
		(layer "B.Cu")
		(net "JTAG_DBP_CPU1_GTL_R_TDI")
	)
	(arc
		(start 104.389682 -219.007944)
		(mid 104.113207 -218.940624)
		(end 103.83901 -219.01658)
		(width 0.0889)
		(layer "B.Cu")
		(net "JTAG_DBP_CPU1_GTL_R_TDI")
	)
	(arc
		(start 87.479124 -215.755982)
		(mid 87.34821 -215.619622)
		(end 87.300562 -215.436704)
		(width 0.0889)
		(layer "B.Cu")
		(net "JTAG_DBP_CPU1_GTL_R_TDI")
	)
	(arc
		(start 112.854232 -230.40594)
		(mid 112.723318 -230.26958)
		(end 112.67567 -230.086662)
		(width 0.0889)
		(layer "B.Cu")
		(net "JTAG_DBP_CPU1_GTL_R_TDI")
	)
	(arc
		(start 111.735616 -228.440488)
		(mid 111.655454 -228.168299)
		(end 111.453168 -227.969318)
		(width 0.0889)
		(layer "B.Cu")
		(net "JTAG_DBP_CPU1_GTL_R_TDI")
	)
	(arc
		(start 110.325916 -226.003104)
		(mid 110.246697 -225.728419)
		(end 110.043214 -225.527616)
		(width 0.0889)
		(layer "B.Cu")
		(net "JTAG_DBP_CPU1_GTL_R_TDI")
	)
	(arc
		(start 98.750882 -219.007944)
		(mid 98.474407 -218.940624)
		(end 98.20021 -219.01658)
		(width 0.0889)
		(layer "B.Cu")
		(net "JTAG_DBP_CPU1_GTL_R_TDI")
	)
	(arc
		(start 104.687116 -219.506038)
		(mid 104.613125 -219.226472)
		(end 104.41051 -219.020136)
		(width 0.0889)
		(layer "B.Cu")
		(net "JTAG_DBP_CPU1_GTL_R_TDI")
	)
	(arc
		(start 88.710516 -217.864182)
		(mid 88.631297 -217.589497)
		(end 88.427814 -217.388694)
		(width 0.0889)
		(layer "B.Cu")
		(net "JTAG_DBP_CPU1_GTL_R_TDI")
	)
	(arc
		(start 110.504478 -226.336606)
		(mid 110.373564 -226.200246)
		(end 110.325916 -226.017328)
		(width 0.0889)
		(layer "B.Cu")
		(net "JTAG_DBP_CPU1_GTL_R_TDI")
	)
	(arc
		(start 112.205516 -229.272846)
		(mid 112.133281 -228.996322)
		(end 111.935006 -228.7905)
		(width 0.0889)
		(layer "B.Cu")
		(net "JTAG_DBP_CPU1_GTL_R_TDI")
	)
	(arc
		(start 107.506516 -221.1197)
		(mid 107.427297 -220.845015)
		(end 107.223814 -220.644212)
		(width 0.0889)
		(layer "B.Cu")
		(net "JTAG_DBP_CPU1_GTL_R_TDI")
	)
	(arc
		(start 89.180416 -218.682316)
		(mid 89.102305 -218.405367)
		(end 88.897968 -218.202764)
		(width 0.0889)
		(layer "B.Cu")
		(net "JTAG_DBP_CPU1_GTL_R_TDI")
	)
	(arc
		(start 97.811082 -219.007944)
		(mid 97.534607 -218.940624)
		(end 97.26041 -219.01658)
		(width 0.0889)
		(layer "B.Cu")
		(net "JTAG_DBP_CPU1_GTL_R_TDI")
	)
	(arc
		(start 94.44101 -219.01658)
		(mid 94.253812 -219.066723)
		(end 94.066614 -219.01658)
		(width 0.0889)
		(layer "B.Cu")
		(net "JTAG_DBP_CPU1_GTL_R_TDI")
	)
	(arc
		(start 109.564678 -224.70872)
		(mid 109.386081 -224.389442)
		(end 109.564678 -224.070164)
		(width 0.0889)
		(layer "B.Cu")
		(net "JTAG_DBP_CPU1_GTL_R_TDI")
	)
	(arc
		(start 101.570282 -219.007944)
		(mid 101.293807 -218.940624)
		(end 101.01961 -219.01658)
		(width 0.0889)
		(layer "B.Cu")
		(net "JTAG_DBP_CPU1_GTL_R_TDI")
	)
	(arc
		(start 88.889078 -218.197684)
		(mid 88.758164 -218.061324)
		(end 88.710516 -217.878406)
		(width 0.0889)
		(layer "B.Cu")
		(net "JTAG_DBP_CPU1_GTL_R_TDI")
	)
	(arc
		(start 112.862614 -233.017568)
		(mid 113.069558 -232.810858)
		(end 113.145316 -232.528364)
		(width 0.0889)
		(layer "B.Cu")
		(net "JTAG_DBP_CPU1_GTL_R_TDI")
	)
	(arc
		(start 113.145316 -230.884984)
		(mid 113.065946 -230.61125)
		(end 112.863122 -230.41102)
		(width 0.0889)
		(layer "B.Cu")
		(net "JTAG_DBP_CPU1_GTL_R_TDI")
	)
	(arc
		(start 109.579664 -224.061528)
		(mid 109.782077 -223.855115)
		(end 109.856016 -223.575626)
		(width 0.0889)
		(layer "B.Cu")
		(net "JTAG_DBP_CPU1_GTL_R_TDI")
	)
	(arc
		(start 109.088682 -222.263462)
		(mid 108.812207 -222.196142)
		(end 108.53801 -222.272098)
		(width 0.0889)
		(layer "B.Cu")
		(net "JTAG_DBP_CPU1_GTL_R_TDI")
	)
	(arc
		(start 109.564678 -223.080834)
		(mid 109.433764 -222.944474)
		(end 109.386116 -222.761556)
		(width 0.0889)
		(layer "B.Cu")
		(net "JTAG_DBP_CPU1_GTL_R_TDI")
	)
	(arc
		(start 91.232482 -219.007944)
		(mid 90.956007 -218.940624)
		(end 90.68181 -219.01658)
		(width 0.0889)
		(layer "B.Cu")
		(net "JTAG_DBP_CPU1_GTL_R_TDI")
	)
	(arc
		(start 110.795816 -226.821238)
		(mid 110.717705 -226.544289)
		(end 110.513368 -226.341686)
		(width 0.0889)
		(layer "B.Cu")
		(net "JTAG_DBP_CPU1_GTL_R_TDI")
	)
	(arc
		(start 111.922814 -228.783388)
		(mid 111.787881 -228.650034)
		(end 111.735616 -228.467666)
		(width 0.0889)
		(layer "B.Cu")
		(net "JTAG_DBP_CPU1_GTL_R_TDI")
	)
	(arc
		(start 90.68181 -219.01658)
		(mid 90.494612 -219.066723)
		(end 90.307414 -219.01658)
		(width 0.0889)
		(layer "B.Cu")
		(net "JTAG_DBP_CPU1_GTL_R_TDI")
	)
	(arc
		(start 106.754168 -219.830396)
		(mid 106.471466 -219.75462)
		(end 106.188764 -219.830396)
		(width 0.0889)
		(layer "B.Cu")
		(net "JTAG_DBP_CPU1_GTL_R_TDI")
	)
	(arc
		(start 102.89921 -219.01658)
		(mid 102.712012 -219.066723)
		(end 102.524814 -219.01658)
		(width 0.0889)
		(layer "B.Cu")
		(net "JTAG_DBP_CPU1_GTL_R_TDI")
	)
	(arc
		(start 95.931482 -219.007944)
		(mid 95.655007 -218.940624)
		(end 95.38081 -219.01658)
		(width 0.0889)
		(layer "B.Cu")
		(net "JTAG_DBP_CPU1_GTL_R_TDI")
	)
	(arc
		(start 97.26041 -219.01658)
		(mid 97.073212 -219.066723)
		(end 96.886014 -219.01658)
		(width 0.0889)
		(layer "B.Cu")
		(net "JTAG_DBP_CPU1_GTL_R_TDI")
	)
	(arc
		(start 91.62161 -219.01658)
		(mid 91.434412 -219.066723)
		(end 91.247214 -219.01658)
		(width 0.0889)
		(layer "B.Cu")
		(net "JTAG_DBP_CPU1_GTL_R_TDI")
	)
	(arc
		(start 94.991682 -219.007944)
		(mid 94.715207 -218.940624)
		(end 94.44101 -219.01658)
		(width 0.0889)
		(layer "B.Cu")
		(net "JTAG_DBP_CPU1_GTL_R_TDI")
	)
	(arc
		(start 108.154724 -222.267018)
		(mid 108.02381 -222.130658)
		(end 107.976162 -221.94774)
		(width 0.0889)
		(layer "B.Cu")
		(net "JTAG_DBP_CPU1_GTL_R_TDI")
	)
	(arc
		(start 98.20021 -219.01658)
		(mid 98.013012 -219.066723)
		(end 97.825814 -219.01658)
		(width 0.0889)
		(layer "B.Cu")
		(net "JTAG_DBP_CPU1_GTL_R_TDI")
	)
	(arc
		(start 104.865678 -219.825316)
		(mid 104.734764 -219.688956)
		(end 104.687116 -219.506038)
		(width 0.0889)
		(layer "B.Cu")
		(net "JTAG_DBP_CPU1_GTL_R_TDI")
	)
	(arc
		(start 109.386116 -222.761556)
		(mid 109.312125 -222.48199)
		(end 109.10951 -222.275654)
		(width 0.0889)
		(layer "B.Cu")
		(net "JTAG_DBP_CPU1_GTL_R_TDI")
	)
	(arc
		(start 99.14001 -219.01658)
		(mid 98.952812 -219.066723)
		(end 98.765614 -219.01658)
		(width 0.0889)
		(layer "B.Cu")
		(net "JTAG_DBP_CPU1_GTL_R_TDI")
	)
	(arc
		(start 112.297464 -233.017822)
		(mid 112.579912 -233.093505)
		(end 112.86236 -233.017822)
		(width 0.0889)
		(layer "B.Cu")
		(net "JTAG_DBP_CPU1_GTL_R_TDI")
	)
	(arc
		(start 90.292682 -219.007944)
		(mid 90.016207 -218.940624)
		(end 89.74201 -219.01658)
		(width 0.0889)
		(layer "B.Cu")
		(net "JTAG_DBP_CPU1_GTL_R_TDI")
	)
	(arc
		(start 111.444278 -227.964238)
		(mid 111.313364 -227.827878)
		(end 111.265716 -227.64496)
		(width 0.0889)
		(layer "B.Cu")
		(net "JTAG_DBP_CPU1_GTL_R_TDI")
	)
	(arc
		(start 96.871282 -219.007944)
		(mid 96.594807 -218.940624)
		(end 96.32061 -219.01658)
		(width 0.0889)
		(layer "B.Cu")
		(net "JTAG_DBP_CPU1_GTL_R_TDI")
	)
	(arc
		(start 102.510082 -219.007944)
		(mid 102.233607 -218.940624)
		(end 101.95941 -219.01658)
		(width 0.0889)
		(layer "B.Cu")
		(net "JTAG_DBP_CPU1_GTL_R_TDI")
	)
	(arc
		(start 93.50121 -219.01658)
		(mid 93.314012 -219.066723)
		(end 93.126814 -219.01658)
		(width 0.0889)
		(layer "B.Cu")
		(net "JTAG_DBP_CPU1_GTL_R_TDI")
	)
	(arc
		(start 112.384078 -229.592124)
		(mid 112.253164 -229.455764)
		(end 112.205516 -229.272846)
		(width 0.0889)
		(layer "B.Cu")
		(net "JTAG_DBP_CPU1_GTL_R_TDI")
	)
	(arc
		(start 109.855762 -225.187764)
		(mid 109.776392 -224.91403)
		(end 109.573568 -224.7138)
		(width 0.0889)
		(layer "B.Cu")
		(net "JTAG_DBP_CPU1_GTL_R_TDI")
	)
	(arc
		(start 92.172282 -219.007944)
		(mid 91.895807 -218.940624)
		(end 91.62161 -219.01658)
		(width 0.0889)
		(layer "B.Cu")
		(net "JTAG_DBP_CPU1_GTL_R_TDI")
	)
	(arc
		(start 100.07981 -219.01658)
		(mid 99.892612 -219.066723)
		(end 99.705414 -219.01658)
		(width 0.0889)
		(layer "B.Cu")
		(net "JTAG_DBP_CPU1_GTL_R_TDI")
	)
	(arc
		(start 105.248964 -219.830396)
		(mid 105.061766 -219.880539)
		(end 104.874568 -219.830396)
		(width 0.0889)
		(layer "B.Cu")
		(net "JTAG_DBP_CPU1_GTL_R_TDI")
	)
	(arc
		(start 107.976162 -221.932246)
		(mid 107.896792 -221.658512)
		(end 107.693968 -221.458282)
		(width 0.0889)
		(layer "B.Cu")
		(net "JTAG_DBP_CPU1_GTL_R_TDI")
	)
	(arc
		(start 103.449882 -219.007944)
		(mid 103.173407 -218.940624)
		(end 102.89921 -219.01658)
		(width 0.0889)
		(layer "B.Cu")
		(net "JTAG_DBP_CPU1_GTL_R_TDI")
	)
	(arc
		(start 107.036616 -220.309948)
		(mid 106.958505 -220.032999)
		(end 106.754168 -219.830396)
		(width 0.0889)
		(layer "B.Cu")
		(net "JTAG_DBP_CPU1_GTL_R_TDI")
	)
	(arc
		(start 101.01961 -219.01658)
		(mid 100.832412 -219.066723)
		(end 100.645214 -219.01658)
		(width 0.0889)
		(layer "B.Cu")
		(net "JTAG_DBP_CPU1_GTL_R_TDI")
	)
	(arc
		(start 94.051882 -219.007944)
		(mid 93.775407 -218.940624)
		(end 93.50121 -219.01658)
		(width 0.0889)
		(layer "B.Cu")
		(net "JTAG_DBP_CPU1_GTL_R_TDI")
	)
	(arc
		(start 111.265716 -227.64496)
		(mid 111.191725 -227.365394)
		(end 110.98911 -227.159058)
		(width 0.0889)
		(layer "B.Cu")
		(net "JTAG_DBP_CPU1_GTL_R_TDI")
	)
	(arc
		(start 109.856016 -223.561402)
		(mid 109.776875 -223.286779)
		(end 109.573568 -223.085914)
		(width 0.0889)
		(layer "B.Cu")
		(net "JTAG_DBP_CPU1_GTL_R_TDI")
	)
	(arc
		(start 110.034324 -225.522536)
		(mid 109.90341 -225.386176)
		(end 109.855762 -225.203258)
		(width 0.0889)
		(layer "B.Cu")
		(net "JTAG_DBP_CPU1_GTL_R_TDI")
	)
	(arc
		(start 89.74201 -219.01658)
		(mid 89.554812 -219.066723)
		(end 89.367614 -219.01658)
		(width 0.0889)
		(layer "B.Cu")
		(net "JTAG_DBP_CPU1_GTL_R_TDI")
	)
	(arc
		(start 88.240362 -217.064336)
		(mid 88.166371 -216.78477)
		(end 87.963756 -216.578434)
		(width 0.0889)
		(layer "B.Cu")
		(net "JTAG_DBP_CPU1_GTL_R_TDI")
	)
	(arc
		(start 92.56141 -219.01658)
		(mid 92.374212 -219.066723)
		(end 92.187014 -219.01658)
		(width 0.0889)
		(layer "B.Cu")
		(net "JTAG_DBP_CPU1_GTL_R_TDI")
	)
	(arc
		(start 93.112082 -219.007944)
		(mid 92.835607 -218.940624)
		(end 92.56141 -219.01658)
		(width 0.0889)
		(layer "B.Cu")
		(net "JTAG_DBP_CPU1_GTL_R_TDI")
	)
	(arc
		(start 87.770208 -216.235026)
		(mid 87.690838 -215.961292)
		(end 87.488014 -215.761062)
		(width 0.0889)
		(layer "B.Cu")
		(net "JTAG_DBP_CPU1_GTL_R_TDI")
	)
	(arc
		(start 112.675416 -230.076756)
		(mid 112.597305 -229.799807)
		(end 112.392968 -229.597204)
		(width 0.0889)
		(layer "B.Cu")
		(net "JTAG_DBP_CPU1_GTL_R_TDI")
	)
	(arc
		(start 105.814368 -219.830396)
		(mid 105.540169 -219.754561)
		(end 105.263696 -219.82176)
		(width 0.0889)
		(layer "B.Cu")
		(net "JTAG_DBP_CPU1_GTL_R_TDI")
	)
	(segment
		(start 110.700566 -233.064304)
		(end 110.700566 -232.528364)
		(width 0.12954)
		(layer "F.Cu")
		(net "JTAG_DBP_CPU1_GTL_R_TCK")
	)
	(via
		(at 86.747858 -197.703948)
		(size 0.508)
		(drill 0.254)
		(layers "F.Cu" "B.Cu")
		(net "JTAG_DBP_CPU1_GTL_R_TCK")
	)
	(via
		(at 110.700566 -232.528364)
		(size 0.4572)
		(drill 0.2032)
		(layers "F.Cu" "B.Cu")
		(net "JTAG_DBP_CPU1_GTL_R_TCK")
	)
	(segment
		(start 106.197654 -227.325682)
		(end 106.188764 -227.320602)
		(width 0.0889)
		(layer "B.Cu")
		(net "JTAG_DBP_CPU1_GTL_R_TCK")
	)
	(segment
		(start 84.92998 -222.711264)
		(end 82.046318 -219.827602)
		(width 0.12954)
		(layer "B.Cu")
		(net "JTAG_DBP_CPU1_GTL_R_TCK")
	)
	(segment
		(start 94.066614 -223.251268)
		(end 94.0562 -223.257364)
		(width 0.0889)
		(layer "B.Cu")
		(net "JTAG_DBP_CPU1_GTL_R_TCK")
	)
	(segment
		(start 85.35035 -223.327722)
		(end 85.267292 -223.327722)
		(width 0.0889)
		(layer "B.Cu")
		(net "JTAG_DBP_CPU1_GTL_R_TCK")
	)
	(segment
		(start 104.309164 -224.065084)
		(end 104.296972 -224.057972)
		(width 0.0889)
		(layer "B.Cu")
		(net "JTAG_DBP_CPU1_GTL_R_TCK")
	)
	(segment
		(start 110.700566 -232.528364)
		(end 110.544102 -232.257346)
		(width 0.0889)
		(layer "B.Cu")
		(net "JTAG_DBP_CPU1_GTL_R_TCK")
	)
	(segment
		(start 101.585014 -223.251268)
		(end 101.5746 -223.257364)
		(width 0.0889)
		(layer "B.Cu")
		(net "JTAG_DBP_CPU1_GTL_R_TCK")
	)
	(segment
		(start 86.747858 -191.846708)
		(end 87.489284 -191.105282)
		(width 0.12954)
		(layer "B.Cu")
		(net "JTAG_DBP_CPU1_GTL_R_TCK")
	)
	(segment
		(start 92.187014 -223.251268)
		(end 92.1766 -223.257364)
		(width 0.0889)
		(layer "B.Cu")
		(net "JTAG_DBP_CPU1_GTL_R_TCK")
	)
	(segment
		(start 109.4867 -231.39527)
		(end 109.47781 -231.39019)
		(width 0.0889)
		(layer "B.Cu")
		(net "JTAG_DBP_CPU1_GTL_R_TCK")
	)
	(segment
		(start 103.8479 -223.256348)
		(end 103.83901 -223.251268)
		(width 0.0889)
		(layer "B.Cu")
		(net "JTAG_DBP_CPU1_GTL_R_TCK")
	)
	(segment
		(start 97.825814 -223.251268)
		(end 97.8154 -223.257364)
		(width 0.0889)
		(layer "B.Cu")
		(net "JTAG_DBP_CPU1_GTL_R_TCK")
	)
	(segment
		(start 107.785662 -230.102156)
		(end 107.785662 -230.086662)
		(width 0.0889)
		(layer "B.Cu")
		(net "JTAG_DBP_CPU1_GTL_R_TCK")
	)
	(segment
		(start 104.496616 -224.404936)
		(end 104.496616 -224.389442)
		(width 0.0889)
		(layer "B.Cu")
		(net "JTAG_DBP_CPU1_GTL_R_TCK")
	)
	(segment
		(start 82.046318 -219.827602)
		(end 82.046318 -209.78495)
		(width 0.12954)
		(layer "B.Cu")
		(net "JTAG_DBP_CPU1_GTL_R_TCK")
	)
	(segment
		(start 82.046318 -209.78495)
		(end 84.818474 -207.012794)
		(width 0.12954)
		(layer "B.Cu")
		(net "JTAG_DBP_CPU1_GTL_R_TCK")
	)
	(segment
		(start 84.92998 -222.99041)
		(end 84.92998 -222.711264)
		(width 0.0889)
		(layer "B.Cu")
		(net "JTAG_DBP_CPU1_GTL_R_TCK")
	)
	(segment
		(start 91.247468 -223.251268)
		(end 91.237054 -223.257364)
		(width 0.0889)
		(layer "B.Cu")
		(net "JTAG_DBP_CPU1_GTL_R_TCK")
	)
	(segment
		(start 105.436416 -226.032822)
		(end 105.436416 -226.017328)
		(width 0.0889)
		(layer "B.Cu")
		(net "JTAG_DBP_CPU1_GTL_R_TCK")
	)
	(segment
		(start 106.6673 -228.139752)
		(end 106.65841 -228.134672)
		(width 0.0889)
		(layer "B.Cu")
		(net "JTAG_DBP_CPU1_GTL_R_TCK")
	)
	(segment
		(start 102.525068 -223.251268)
		(end 102.514654 -223.257364)
		(width 0.0889)
		(layer "B.Cu")
		(net "JTAG_DBP_CPU1_GTL_R_TCK")
	)
	(segment
		(start 104.966262 -225.217482)
		(end 104.966262 -225.203258)
		(width 0.0889)
		(layer "B.Cu")
		(net "JTAG_DBP_CPU1_GTL_R_TCK")
	)
	(segment
		(start 104.318054 -224.070164)
		(end 104.309164 -224.065084)
		(width 0.0889)
		(layer "B.Cu")
		(net "JTAG_DBP_CPU1_GTL_R_TCK")
	)
	(segment
		(start 88.43645 -223.246442)
		(end 88.428068 -223.251268)
		(width 0.0889)
		(layer "B.Cu")
		(net "JTAG_DBP_CPU1_GTL_R_TCK")
	)
	(segment
		(start 106.376216 -227.667058)
		(end 106.376216 -227.64496)
		(width 0.0889)
		(layer "B.Cu")
		(net "JTAG_DBP_CPU1_GTL_R_TCK")
	)
	(segment
		(start 85.608668 -223.251268)
		(end 85.578696 -223.268794)
		(width 0.0889)
		(layer "B.Cu")
		(net "JTAG_DBP_CPU1_GTL_R_TCK")
	)
	(segment
		(start 105.7275 -226.511866)
		(end 105.71861 -226.506786)
		(width 0.0889)
		(layer "B.Cu")
		(net "JTAG_DBP_CPU1_GTL_R_TCK")
	)
	(segment
		(start 86.747858 -201.059034)
		(end 86.747858 -197.703948)
		(width 0.12954)
		(layer "B.Cu")
		(net "JTAG_DBP_CPU1_GTL_R_TCK")
	)
	(segment
		(start 86.747858 -197.703948)
		(end 86.747858 -191.846708)
		(width 0.12954)
		(layer "B.Cu")
		(net "JTAG_DBP_CPU1_GTL_R_TCK")
	)
	(segment
		(start 95.946214 -223.251268)
		(end 95.9358 -223.257364)
		(width 0.0889)
		(layer "B.Cu")
		(net "JTAG_DBP_CPU1_GTL_R_TCK")
	)
	(segment
		(start 85.267292 -223.327722)
		(end 84.92998 -222.99041)
		(width 0.0889)
		(layer "B.Cu")
		(net "JTAG_DBP_CPU1_GTL_R_TCK")
	)
	(segment
		(start 109.195362 -230.922576)
		(end 109.195362 -230.891842)
		(width 0.0889)
		(layer "B.Cu")
		(net "JTAG_DBP_CPU1_GTL_R_TCK")
	)
	(segment
		(start 93.127068 -223.251268)
		(end 93.116654 -223.257364)
		(width 0.0889)
		(layer "B.Cu")
		(net "JTAG_DBP_CPU1_GTL_R_TCK")
	)
	(segment
		(start 90.307414 -223.251268)
		(end 90.297 -223.257364)
		(width 0.0889)
		(layer "B.Cu")
		(net "JTAG_DBP_CPU1_GTL_R_TCK")
	)
	(segment
		(start 89.367868 -223.251268)
		(end 89.357454 -223.257364)
		(width 0.0889)
		(layer "B.Cu")
		(net "JTAG_DBP_CPU1_GTL_R_TCK")
	)
	(segment
		(start 109.947964 -232.204006)
		(end 109.935772 -232.196894)
		(width 0.0889)
		(layer "B.Cu")
		(net "JTAG_DBP_CPU1_GTL_R_TCK")
	)
	(segment
		(start 84.818474 -202.988418)
		(end 86.747858 -201.059034)
		(width 0.12954)
		(layer "B.Cu")
		(net "JTAG_DBP_CPU1_GTL_R_TCK")
	)
	(segment
		(start 98.765868 -223.251268)
		(end 98.755454 -223.257364)
		(width 0.0889)
		(layer "B.Cu")
		(net "JTAG_DBP_CPU1_GTL_R_TCK")
	)
	(segment
		(start 110.544102 -232.257346)
		(end 110.454948 -232.23347)
		(width 0.0889)
		(layer "B.Cu")
		(net "JTAG_DBP_CPU1_GTL_R_TCK")
	)
	(segment
		(start 104.7877 -224.88398)
		(end 104.77881 -224.8789)
		(width 0.0889)
		(layer "B.Cu")
		(net "JTAG_DBP_CPU1_GTL_R_TCK")
	)
	(segment
		(start 88.428068 -223.251268)
		(end 88.413336 -223.259904)
		(width 0.0889)
		(layer "B.Cu")
		(net "JTAG_DBP_CPU1_GTL_R_TCK")
	)
	(segment
		(start 96.886268 -223.251268)
		(end 96.875854 -223.257364)
		(width 0.0889)
		(layer "B.Cu")
		(net "JTAG_DBP_CPU1_GTL_R_TCK")
	)
	(segment
		(start 105.257854 -225.69805)
		(end 105.248964 -225.69297)
		(width 0.0889)
		(layer "B.Cu")
		(net "JTAG_DBP_CPU1_GTL_R_TCK")
	)
	(segment
		(start 107.6071 -229.767384)
		(end 107.59821 -229.762304)
		(width 0.0889)
		(layer "B.Cu")
		(net "JTAG_DBP_CPU1_GTL_R_TCK")
	)
	(segment
		(start 103.464614 -223.251268)
		(end 103.4542 -223.257364)
		(width 0.0889)
		(layer "B.Cu")
		(net "JTAG_DBP_CPU1_GTL_R_TCK")
	)
	(segment
		(start 84.818474 -207.012794)
		(end 84.818474 -202.988418)
		(width 0.12954)
		(layer "B.Cu")
		(net "JTAG_DBP_CPU1_GTL_R_TCK")
	)
	(segment
		(start 107.128564 -228.948488)
		(end 107.122468 -228.944932)
		(width 0.0889)
		(layer "B.Cu")
		(net "JTAG_DBP_CPU1_GTL_R_TCK")
	)
	(segment
		(start 107.137454 -228.953568)
		(end 107.128564 -228.948488)
		(width 0.0889)
		(layer "B.Cu")
		(net "JTAG_DBP_CPU1_GTL_R_TCK")
	)
	(segment
		(start 99.705414 -223.251268)
		(end 99.695 -223.257364)
		(width 0.0889)
		(layer "B.Cu")
		(net "JTAG_DBP_CPU1_GTL_R_TCK")
	)
	(segment
		(start 106.188764 -227.320602)
		(end 106.176572 -227.31349)
		(width 0.0889)
		(layer "B.Cu")
		(net "JTAG_DBP_CPU1_GTL_R_TCK")
	)
	(segment
		(start 100.645468 -223.251268)
		(end 100.635054 -223.257364)
		(width 0.0889)
		(layer "B.Cu")
		(net "JTAG_DBP_CPU1_GTL_R_TCK")
	)
	(segment
		(start 95.006668 -223.251268)
		(end 94.996254 -223.257364)
		(width 0.0889)
		(layer "B.Cu")
		(net "JTAG_DBP_CPU1_GTL_R_TCK")
	)
	(segment
		(start 107.316016 -229.28834)
		(end 107.316016 -229.272846)
		(width 0.0889)
		(layer "B.Cu")
		(net "JTAG_DBP_CPU1_GTL_R_TCK")
	)
	(arc
		(start 105.436416 -226.017328)
		(mid 105.388737 -225.834428)
		(end 105.257854 -225.69805)
		(width 0.0889)
		(layer "B.Cu")
		(net "JTAG_DBP_CPU1_GTL_R_TCK")
	)
	(arc
		(start 105.906062 -226.831144)
		(mid 105.858383 -226.648244)
		(end 105.7275 -226.511866)
		(width 0.0889)
		(layer "B.Cu")
		(net "JTAG_DBP_CPU1_GTL_R_TCK")
	)
	(arc
		(start 95.9358 -223.257364)
		(mid 95.657622 -223.327056)
		(end 95.381064 -223.251268)
		(width 0.0889)
		(layer "B.Cu")
		(net "JTAG_DBP_CPU1_GTL_R_TCK")
	)
	(arc
		(start 109.008164 -230.57612)
		(mid 108.820966 -230.525977)
		(end 108.633768 -230.57612)
		(width 0.0889)
		(layer "B.Cu")
		(net "JTAG_DBP_CPU1_GTL_R_TCK")
	)
	(arc
		(start 106.65841 -228.134672)
		(mid 106.457128 -227.937185)
		(end 106.376216 -227.667058)
		(width 0.0889)
		(layer "B.Cu")
		(net "JTAG_DBP_CPU1_GTL_R_TCK")
	)
	(arc
		(start 91.621864 -223.251268)
		(mid 91.434666 -223.201125)
		(end 91.247468 -223.251268)
		(width 0.0889)
		(layer "B.Cu")
		(net "JTAG_DBP_CPU1_GTL_R_TCK")
	)
	(arc
		(start 105.71861 -226.506786)
		(mid 105.515787 -226.306555)
		(end 105.436416 -226.032822)
		(width 0.0889)
		(layer "B.Cu")
		(net "JTAG_DBP_CPU1_GTL_R_TCK")
	)
	(arc
		(start 85.578696 -223.268794)
		(mid 85.467624 -223.310278)
		(end 85.35035 -223.327722)
		(width 0.0889)
		(layer "B.Cu")
		(net "JTAG_DBP_CPU1_GTL_R_TCK")
	)
	(arc
		(start 94.996254 -223.257364)
		(mid 94.717822 -223.327178)
		(end 94.44101 -223.251268)
		(width 0.0889)
		(layer "B.Cu")
		(net "JTAG_DBP_CPU1_GTL_R_TCK")
	)
	(arc
		(start 94.44101 -223.251268)
		(mid 94.253812 -223.201125)
		(end 94.066614 -223.251268)
		(width 0.0889)
		(layer "B.Cu")
		(net "JTAG_DBP_CPU1_GTL_R_TCK")
	)
	(arc
		(start 104.966262 -225.203258)
		(mid 104.918583 -225.020358)
		(end 104.7877 -224.88398)
		(width 0.0889)
		(layer "B.Cu")
		(net "JTAG_DBP_CPU1_GTL_R_TCK")
	)
	(arc
		(start 101.95941 -223.251268)
		(mid 101.772212 -223.201125)
		(end 101.585014 -223.251268)
		(width 0.0889)
		(layer "B.Cu")
		(net "JTAG_DBP_CPU1_GTL_R_TCK")
	)
	(arc
		(start 96.875854 -223.257364)
		(mid 96.597422 -223.327178)
		(end 96.32061 -223.251268)
		(width 0.0889)
		(layer "B.Cu")
		(net "JTAG_DBP_CPU1_GTL_R_TCK")
	)
	(arc
		(start 87.862664 -223.251268)
		(mid 87.675466 -223.201125)
		(end 87.488268 -223.251268)
		(width 0.0889)
		(layer "B.Cu")
		(net "JTAG_DBP_CPU1_GTL_R_TCK")
	)
	(arc
		(start 109.195362 -230.891842)
		(mid 109.143092 -230.709477)
		(end 109.008164 -230.57612)
		(width 0.0889)
		(layer "B.Cu")
		(net "JTAG_DBP_CPU1_GTL_R_TCK")
	)
	(arc
		(start 109.935772 -232.196894)
		(mid 109.737544 -231.991046)
		(end 109.665262 -231.714548)
		(width 0.0889)
		(layer "B.Cu")
		(net "JTAG_DBP_CPU1_GTL_R_TCK")
	)
	(arc
		(start 101.019864 -223.251268)
		(mid 100.832666 -223.201125)
		(end 100.645468 -223.251268)
		(width 0.0889)
		(layer "B.Cu")
		(net "JTAG_DBP_CPU1_GTL_R_TCK")
	)
	(arc
		(start 105.248964 -225.69297)
		(mid 105.045483 -225.492166)
		(end 104.966262 -225.217482)
		(width 0.0889)
		(layer "B.Cu")
		(net "JTAG_DBP_CPU1_GTL_R_TCK")
	)
	(arc
		(start 98.20021 -223.251268)
		(mid 98.013012 -223.201125)
		(end 97.825814 -223.251268)
		(width 0.0889)
		(layer "B.Cu")
		(net "JTAG_DBP_CPU1_GTL_R_TCK")
	)
	(arc
		(start 108.633768 -230.57612)
		(mid 108.350812 -230.652023)
		(end 108.067856 -230.57612)
		(width 0.0889)
		(layer "B.Cu")
		(net "JTAG_DBP_CPU1_GTL_R_TCK")
	)
	(arc
		(start 106.176572 -227.31349)
		(mid 105.978344 -227.107642)
		(end 105.906062 -226.831144)
		(width 0.0889)
		(layer "B.Cu")
		(net "JTAG_DBP_CPU1_GTL_R_TCK")
	)
	(arc
		(start 107.785662 -230.086662)
		(mid 107.737983 -229.903762)
		(end 107.6071 -229.767384)
		(width 0.0889)
		(layer "B.Cu")
		(net "JTAG_DBP_CPU1_GTL_R_TCK")
	)
	(arc
		(start 87.488268 -223.251268)
		(mid 87.205566 -223.32701)
		(end 86.922864 -223.251268)
		(width 0.0889)
		(layer "B.Cu")
		(net "JTAG_DBP_CPU1_GTL_R_TCK")
	)
	(arc
		(start 88.80221 -223.251268)
		(mid 88.619959 -223.201157)
		(end 88.43645 -223.246442)
		(width 0.0889)
		(layer "B.Cu")
		(net "JTAG_DBP_CPU1_GTL_R_TCK")
	)
	(arc
		(start 86.922864 -223.251268)
		(mid 86.735666 -223.201125)
		(end 86.548468 -223.251268)
		(width 0.0889)
		(layer "B.Cu")
		(net "JTAG_DBP_CPU1_GTL_R_TCK")
	)
	(arc
		(start 109.665262 -231.714548)
		(mid 109.617583 -231.531648)
		(end 109.4867 -231.39527)
		(width 0.0889)
		(layer "B.Cu")
		(net "JTAG_DBP_CPU1_GTL_R_TCK")
	)
	(arc
		(start 104.496616 -224.389442)
		(mid 104.448937 -224.206542)
		(end 104.318054 -224.070164)
		(width 0.0889)
		(layer "B.Cu")
		(net "JTAG_DBP_CPU1_GTL_R_TCK")
	)
	(arc
		(start 108.067856 -230.57612)
		(mid 107.865033 -230.375889)
		(end 107.785662 -230.102156)
		(width 0.0889)
		(layer "B.Cu")
		(net "JTAG_DBP_CPU1_GTL_R_TCK")
	)
	(arc
		(start 97.8154 -223.257364)
		(mid 97.537222 -223.327056)
		(end 97.260664 -223.251268)
		(width 0.0889)
		(layer "B.Cu")
		(net "JTAG_DBP_CPU1_GTL_R_TCK")
	)
	(arc
		(start 104.296972 -224.057972)
		(mid 104.098744 -223.852124)
		(end 104.026462 -223.575626)
		(width 0.0889)
		(layer "B.Cu")
		(net "JTAG_DBP_CPU1_GTL_R_TCK")
	)
	(arc
		(start 90.297 -223.257364)
		(mid 90.018822 -223.327056)
		(end 89.742264 -223.251268)
		(width 0.0889)
		(layer "B.Cu")
		(net "JTAG_DBP_CPU1_GTL_R_TCK")
	)
	(arc
		(start 106.845862 -228.45903)
		(mid 106.798183 -228.27613)
		(end 106.6673 -228.139752)
		(width 0.0889)
		(layer "B.Cu")
		(net "JTAG_DBP_CPU1_GTL_R_TCK")
	)
	(arc
		(start 86.548468 -223.251268)
		(mid 86.265766 -223.32701)
		(end 85.983064 -223.251268)
		(width 0.0889)
		(layer "B.Cu")
		(net "JTAG_DBP_CPU1_GTL_R_TCK")
	)
	(arc
		(start 107.316016 -229.272846)
		(mid 107.268337 -229.089946)
		(end 107.137454 -228.953568)
		(width 0.0889)
		(layer "B.Cu")
		(net "JTAG_DBP_CPU1_GTL_R_TCK")
	)
	(arc
		(start 92.56141 -223.251268)
		(mid 92.374212 -223.201125)
		(end 92.187014 -223.251268)
		(width 0.0889)
		(layer "B.Cu")
		(net "JTAG_DBP_CPU1_GTL_R_TCK")
	)
	(arc
		(start 85.983064 -223.251268)
		(mid 85.795866 -223.201125)
		(end 85.608668 -223.251268)
		(width 0.0889)
		(layer "B.Cu")
		(net "JTAG_DBP_CPU1_GTL_R_TCK")
	)
	(arc
		(start 93.116654 -223.257364)
		(mid 92.838222 -223.327178)
		(end 92.56141 -223.251268)
		(width 0.0889)
		(layer "B.Cu")
		(net "JTAG_DBP_CPU1_GTL_R_TCK")
	)
	(arc
		(start 103.4542 -223.257364)
		(mid 103.176022 -223.327056)
		(end 102.899464 -223.251268)
		(width 0.0889)
		(layer "B.Cu")
		(net "JTAG_DBP_CPU1_GTL_R_TCK")
	)
	(arc
		(start 95.381064 -223.251268)
		(mid 95.193866 -223.201125)
		(end 95.006668 -223.251268)
		(width 0.0889)
		(layer "B.Cu")
		(net "JTAG_DBP_CPU1_GTL_R_TCK")
	)
	(arc
		(start 97.260664 -223.251268)
		(mid 97.073466 -223.201125)
		(end 96.886268 -223.251268)
		(width 0.0889)
		(layer "B.Cu")
		(net "JTAG_DBP_CPU1_GTL_R_TCK")
	)
	(arc
		(start 89.742264 -223.251268)
		(mid 89.555066 -223.201125)
		(end 89.367868 -223.251268)
		(width 0.0889)
		(layer "B.Cu")
		(net "JTAG_DBP_CPU1_GTL_R_TCK")
	)
	(arc
		(start 106.376216 -227.64496)
		(mid 106.328537 -227.46206)
		(end 106.197654 -227.325682)
		(width 0.0889)
		(layer "B.Cu")
		(net "JTAG_DBP_CPU1_GTL_R_TCK")
	)
	(arc
		(start 91.237054 -223.257364)
		(mid 90.958622 -223.327178)
		(end 90.68181 -223.251268)
		(width 0.0889)
		(layer "B.Cu")
		(net "JTAG_DBP_CPU1_GTL_R_TCK")
	)
	(arc
		(start 101.5746 -223.257364)
		(mid 101.296422 -223.327056)
		(end 101.019864 -223.251268)
		(width 0.0889)
		(layer "B.Cu")
		(net "JTAG_DBP_CPU1_GTL_R_TCK")
	)
	(arc
		(start 88.413336 -223.259904)
		(mid 88.136895 -223.32707)
		(end 87.862664 -223.251268)
		(width 0.0889)
		(layer "B.Cu")
		(net "JTAG_DBP_CPU1_GTL_R_TCK")
	)
	(arc
		(start 90.68181 -223.251268)
		(mid 90.494612 -223.201125)
		(end 90.307414 -223.251268)
		(width 0.0889)
		(layer "B.Cu")
		(net "JTAG_DBP_CPU1_GTL_R_TCK")
	)
	(arc
		(start 100.07981 -223.251268)
		(mid 99.892612 -223.201125)
		(end 99.705414 -223.251268)
		(width 0.0889)
		(layer "B.Cu")
		(net "JTAG_DBP_CPU1_GTL_R_TCK")
	)
	(arc
		(start 107.59821 -229.762304)
		(mid 107.395387 -229.562073)
		(end 107.316016 -229.28834)
		(width 0.0889)
		(layer "B.Cu")
		(net "JTAG_DBP_CPU1_GTL_R_TCK")
	)
	(arc
		(start 103.83901 -223.251268)
		(mid 103.651812 -223.201125)
		(end 103.464614 -223.251268)
		(width 0.0889)
		(layer "B.Cu")
		(net "JTAG_DBP_CPU1_GTL_R_TCK")
	)
	(arc
		(start 100.635054 -223.257364)
		(mid 100.356622 -223.327178)
		(end 100.07981 -223.251268)
		(width 0.0889)
		(layer "B.Cu")
		(net "JTAG_DBP_CPU1_GTL_R_TCK")
	)
	(arc
		(start 99.140264 -223.251268)
		(mid 98.953066 -223.201125)
		(end 98.765868 -223.251268)
		(width 0.0889)
		(layer "B.Cu")
		(net "JTAG_DBP_CPU1_GTL_R_TCK")
	)
	(arc
		(start 104.77881 -224.8789)
		(mid 104.575987 -224.678669)
		(end 104.496616 -224.404936)
		(width 0.0889)
		(layer "B.Cu")
		(net "JTAG_DBP_CPU1_GTL_R_TCK")
	)
	(arc
		(start 94.0562 -223.257364)
		(mid 93.778022 -223.327056)
		(end 93.501464 -223.251268)
		(width 0.0889)
		(layer "B.Cu")
		(net "JTAG_DBP_CPU1_GTL_R_TCK")
	)
	(arc
		(start 89.357454 -223.257364)
		(mid 89.079022 -223.327178)
		(end 88.80221 -223.251268)
		(width 0.0889)
		(layer "B.Cu")
		(net "JTAG_DBP_CPU1_GTL_R_TCK")
	)
	(arc
		(start 99.695 -223.257364)
		(mid 99.416822 -223.327056)
		(end 99.140264 -223.251268)
		(width 0.0889)
		(layer "B.Cu")
		(net "JTAG_DBP_CPU1_GTL_R_TCK")
	)
	(arc
		(start 102.899464 -223.251268)
		(mid 102.712266 -223.201125)
		(end 102.525068 -223.251268)
		(width 0.0889)
		(layer "B.Cu")
		(net "JTAG_DBP_CPU1_GTL_R_TCK")
	)
	(arc
		(start 104.026462 -223.575626)
		(mid 103.978783 -223.392726)
		(end 103.8479 -223.256348)
		(width 0.0889)
		(layer "B.Cu")
		(net "JTAG_DBP_CPU1_GTL_R_TCK")
	)
	(arc
		(start 96.32061 -223.251268)
		(mid 96.133412 -223.201125)
		(end 95.946214 -223.251268)
		(width 0.0889)
		(layer "B.Cu")
		(net "JTAG_DBP_CPU1_GTL_R_TCK")
	)
	(arc
		(start 107.122468 -228.944932)
		(mid 106.919881 -228.738581)
		(end 106.845862 -228.45903)
		(width 0.0889)
		(layer "B.Cu")
		(net "JTAG_DBP_CPU1_GTL_R_TCK")
	)
	(arc
		(start 102.514654 -223.257364)
		(mid 102.236222 -223.327178)
		(end 101.95941 -223.251268)
		(width 0.0889)
		(layer "B.Cu")
		(net "JTAG_DBP_CPU1_GTL_R_TCK")
	)
	(arc
		(start 109.47781 -231.39019)
		(mid 109.276354 -231.192765)
		(end 109.195362 -230.922576)
		(width 0.0889)
		(layer "B.Cu")
		(net "JTAG_DBP_CPU1_GTL_R_TCK")
	)
	(arc
		(start 110.454948 -232.23347)
		(mid 110.197949 -232.278917)
		(end 109.947964 -232.204006)
		(width 0.0889)
		(layer "B.Cu")
		(net "JTAG_DBP_CPU1_GTL_R_TCK")
	)
	(arc
		(start 98.755454 -223.257364)
		(mid 98.477022 -223.327178)
		(end 98.20021 -223.251268)
		(width 0.0889)
		(layer "B.Cu")
		(net "JTAG_DBP_CPU1_GTL_R_TCK")
	)
	(arc
		(start 93.501464 -223.251268)
		(mid 93.314266 -223.201125)
		(end 93.127068 -223.251268)
		(width 0.0889)
		(layer "B.Cu")
		(net "JTAG_DBP_CPU1_GTL_R_TCK")
	)
	(arc
		(start 92.1766 -223.257364)
		(mid 91.898422 -223.327056)
		(end 91.621864 -223.251268)
		(width 0.0889)
		(layer "B.Cu")
		(net "JTAG_DBP_CPU1_GTL_R_TCK")
	)
	(segment
		(start 358.170734 -233.87812)
		(end 358.170734 -233.34218)
		(width 0.12954)
		(layer "F.Cu")
		(net "JTAG_DBP_CPU0_QS_GTL_R_TMS")
	)
	(via
		(at 358.170734 -233.34218)
		(size 0.4572)
		(drill 0.2032)
		(layers "F.Cu" "B.Cu")
		(net "JTAG_DBP_CPU0_QS_GTL_R_TMS")
	)
	(via
		(at 327.069196 -217.49766)
		(size 0.7112)
		(drill 0.3556)
		(layers "F.Cu" "B.Cu")
		(net "JTAG_DBP_CPU0_QS_GTL_R_TMS")
	)
	(segment
		(start 354.11664 -227.31349)
		(end 354.137722 -227.325682)
		(width 0.0889)
		(layer "B.Cu")
		(net "JTAG_DBP_CPU0_QS_GTL_R_TMS")
	)
	(segment
		(start 346.695522 -223.257364)
		(end 346.705936 -223.251268)
		(width 0.0889)
		(layer "B.Cu")
		(net "JTAG_DBP_CPU0_QS_GTL_R_TMS")
	)
	(segment
		(start 331.682852 -222.111316)
		(end 332.2701 -222.111316)
		(width 0.12954)
		(layer "B.Cu")
		(net "JTAG_DBP_CPU0_QS_GTL_R_TMS")
	)
	(segment
		(start 345.755468 -223.257364)
		(end 345.765882 -223.251268)
		(width 0.0889)
		(layer "B.Cu")
		(net "JTAG_DBP_CPU0_QS_GTL_R_TMS")
	)
	(segment
		(start 357.60533 -231.775762)
		(end 358.170734 -232.341166)
		(width 0.0889)
		(layer "B.Cu")
		(net "JTAG_DBP_CPU0_QS_GTL_R_TMS")
	)
	(segment
		(start 342.936322 -223.257364)
		(end 342.946736 -223.251268)
		(width 0.0889)
		(layer "B.Cu")
		(net "JTAG_DBP_CPU0_QS_GTL_R_TMS")
	)
	(segment
		(start 352.436684 -224.389442)
		(end 352.436684 -224.404936)
		(width 0.0889)
		(layer "B.Cu")
		(net "JTAG_DBP_CPU0_QS_GTL_R_TMS")
	)
	(segment
		(start 355.062536 -228.944932)
		(end 355.077522 -228.953568)
		(width 0.0889)
		(layer "B.Cu")
		(net "JTAG_DBP_CPU0_QS_GTL_R_TMS")
	)
	(segment
		(start 327.069196 -217.49766)
		(end 331.682852 -222.111316)
		(width 0.12954)
		(layer "B.Cu")
		(net "JTAG_DBP_CPU0_QS_GTL_R_TMS")
	)
	(segment
		(start 357.60533 -231.714548)
		(end 357.60533 -231.775762)
		(width 0.0889)
		(layer "B.Cu")
		(net "JTAG_DBP_CPU0_QS_GTL_R_TMS")
	)
	(segment
		(start 332.870048 -222.99041)
		(end 333.20736 -223.327722)
		(width 0.0889)
		(layer "B.Cu")
		(net "JTAG_DBP_CPU0_QS_GTL_R_TMS")
	)
	(segment
		(start 347.635068 -223.257364)
		(end 347.645482 -223.251268)
		(width 0.0889)
		(layer "B.Cu")
		(net "JTAG_DBP_CPU0_QS_GTL_R_TMS")
	)
	(segment
		(start 349.514668 -223.257364)
		(end 349.525082 -223.251268)
		(width 0.0889)
		(layer "B.Cu")
		(net "JTAG_DBP_CPU0_QS_GTL_R_TMS")
	)
	(segment
		(start 352.90633 -225.203258)
		(end 352.90633 -225.217482)
		(width 0.0889)
		(layer "B.Cu")
		(net "JTAG_DBP_CPU0_QS_GTL_R_TMS")
	)
	(segment
		(start 348.575122 -223.257364)
		(end 348.585536 -223.251268)
		(width 0.0889)
		(layer "B.Cu")
		(net "JTAG_DBP_CPU0_QS_GTL_R_TMS")
	)
	(segment
		(start 352.23704 -224.057972)
		(end 352.258122 -224.070164)
		(width 0.0889)
		(layer "B.Cu")
		(net "JTAG_DBP_CPU0_QS_GTL_R_TMS")
	)
	(segment
		(start 350.454722 -223.257364)
		(end 350.465136 -223.251268)
		(width 0.0889)
		(layer "B.Cu")
		(net "JTAG_DBP_CPU0_QS_GTL_R_TMS")
	)
	(segment
		(start 332.771496 -222.612712)
		(end 332.771496 -222.891858)
		(width 0.12954)
		(layer "B.Cu")
		(net "JTAG_DBP_CPU0_QS_GTL_R_TMS")
	)
	(segment
		(start 337.297522 -223.257364)
		(end 337.307936 -223.251268)
		(width 0.0889)
		(layer "B.Cu")
		(net "JTAG_DBP_CPU0_QS_GTL_R_TMS")
	)
	(segment
		(start 341.996268 -223.257364)
		(end 342.006682 -223.251268)
		(width 0.0889)
		(layer "B.Cu")
		(net "JTAG_DBP_CPU0_QS_GTL_R_TMS")
	)
	(segment
		(start 338.237068 -223.257364)
		(end 338.247482 -223.251268)
		(width 0.0889)
		(layer "B.Cu")
		(net "JTAG_DBP_CPU0_QS_GTL_R_TMS")
	)
	(segment
		(start 353.658678 -226.506786)
		(end 353.667568 -226.511866)
		(width 0.0889)
		(layer "B.Cu")
		(net "JTAG_DBP_CPU0_QS_GTL_R_TMS")
	)
	(segment
		(start 355.72573 -230.086662)
		(end 355.72573 -230.102156)
		(width 0.0889)
		(layer "B.Cu")
		(net "JTAG_DBP_CPU0_QS_GTL_R_TMS")
	)
	(segment
		(start 332.2701 -222.111316)
		(end 332.771496 -222.612712)
		(width 0.12954)
		(layer "B.Cu")
		(net "JTAG_DBP_CPU0_QS_GTL_R_TMS")
	)
	(segment
		(start 340.116668 -223.257364)
		(end 340.127082 -223.251268)
		(width 0.0889)
		(layer "B.Cu")
		(net "JTAG_DBP_CPU0_QS_GTL_R_TMS")
	)
	(segment
		(start 355.538278 -229.762304)
		(end 355.547168 -229.767384)
		(width 0.0889)
		(layer "B.Cu")
		(net "JTAG_DBP_CPU0_QS_GTL_R_TMS")
	)
	(segment
		(start 354.316284 -227.64496)
		(end 354.316284 -227.667058)
		(width 0.0889)
		(layer "B.Cu")
		(net "JTAG_DBP_CPU0_QS_GTL_R_TMS")
	)
	(segment
		(start 336.353404 -223.259904)
		(end 336.376518 -223.246442)
		(width 0.0889)
		(layer "B.Cu")
		(net "JTAG_DBP_CPU0_QS_GTL_R_TMS")
	)
	(segment
		(start 341.056722 -223.257364)
		(end 341.067136 -223.251268)
		(width 0.0889)
		(layer "B.Cu")
		(net "JTAG_DBP_CPU0_QS_GTL_R_TMS")
	)
	(segment
		(start 333.20736 -223.327722)
		(end 333.290418 -223.327722)
		(width 0.0889)
		(layer "B.Cu")
		(net "JTAG_DBP_CPU0_QS_GTL_R_TMS")
	)
	(segment
		(start 333.518764 -223.268794)
		(end 333.548736 -223.251268)
		(width 0.0889)
		(layer "B.Cu")
		(net "JTAG_DBP_CPU0_QS_GTL_R_TMS")
	)
	(segment
		(start 326.297798 -189.33668)
		(end 326.297798 -216.726262)
		(width 0.12954)
		(layer "B.Cu")
		(net "JTAG_DBP_CPU0_QS_GTL_R_TMS")
	)
	(segment
		(start 332.771496 -222.891858)
		(end 332.870048 -222.99041)
		(width 0.12954)
		(layer "B.Cu")
		(net "JTAG_DBP_CPU0_QS_GTL_R_TMS")
	)
	(segment
		(start 352.718878 -224.8789)
		(end 352.727768 -224.88398)
		(width 0.0889)
		(layer "B.Cu")
		(net "JTAG_DBP_CPU0_QS_GTL_R_TMS")
	)
	(segment
		(start 355.256084 -229.272846)
		(end 355.256084 -229.28834)
		(width 0.0889)
		(layer "B.Cu")
		(net "JTAG_DBP_CPU0_QS_GTL_R_TMS")
	)
	(segment
		(start 343.875868 -223.257364)
		(end 343.886282 -223.251268)
		(width 0.0889)
		(layer "B.Cu")
		(net "JTAG_DBP_CPU0_QS_GTL_R_TMS")
	)
	(segment
		(start 354.598478 -228.134672)
		(end 354.607368 -228.139752)
		(width 0.0889)
		(layer "B.Cu")
		(net "JTAG_DBP_CPU0_QS_GTL_R_TMS")
	)
	(segment
		(start 357.13543 -230.891842)
		(end 357.13543 -230.922576)
		(width 0.0889)
		(layer "B.Cu")
		(net "JTAG_DBP_CPU0_QS_GTL_R_TMS")
	)
	(segment
		(start 326.297798 -216.726262)
		(end 327.069196 -217.49766)
		(width 0.12954)
		(layer "B.Cu")
		(net "JTAG_DBP_CPU0_QS_GTL_R_TMS")
	)
	(segment
		(start 357.417878 -231.39019)
		(end 357.426768 -231.39527)
		(width 0.0889)
		(layer "B.Cu")
		(net "JTAG_DBP_CPU0_QS_GTL_R_TMS")
	)
	(segment
		(start 353.189032 -225.69297)
		(end 353.197922 -225.69805)
		(width 0.0889)
		(layer "B.Cu")
		(net "JTAG_DBP_CPU0_QS_GTL_R_TMS")
	)
	(segment
		(start 344.815922 -223.257364)
		(end 344.826336 -223.251268)
		(width 0.0889)
		(layer "B.Cu")
		(net "JTAG_DBP_CPU0_QS_GTL_R_TMS")
	)
	(segment
		(start 358.170734 -232.341166)
		(end 358.170734 -233.34218)
		(width 0.0889)
		(layer "B.Cu")
		(net "JTAG_DBP_CPU0_QS_GTL_R_TMS")
	)
	(segment
		(start 339.177122 -223.257364)
		(end 339.187536 -223.251268)
		(width 0.0889)
		(layer "B.Cu")
		(net "JTAG_DBP_CPU0_QS_GTL_R_TMS")
	)
	(segment
		(start 351.394268 -223.257364)
		(end 351.404682 -223.251268)
		(width 0.0889)
		(layer "B.Cu")
		(net "JTAG_DBP_CPU0_QS_GTL_R_TMS")
	)
	(segment
		(start 326.338438 -189.29604)
		(end 326.297798 -189.33668)
		(width 0.12954)
		(layer "B.Cu")
		(net "JTAG_DBP_CPU0_QS_GTL_R_TMS")
	)
	(segment
		(start 353.376484 -226.017328)
		(end 353.376484 -226.032822)
		(width 0.0889)
		(layer "B.Cu")
		(net "JTAG_DBP_CPU0_QS_GTL_R_TMS")
	)
	(arc
		(start 344.260678 -223.251268)
		(mid 344.537491 -223.327104)
		(end 344.815922 -223.257364)
		(width 0.0889)
		(layer "B.Cu")
		(net "JTAG_DBP_CPU0_QS_GTL_R_TMS")
	)
	(arc
		(start 338.247482 -223.251268)
		(mid 338.43468 -223.201125)
		(end 338.621878 -223.251268)
		(width 0.0889)
		(layer "B.Cu")
		(net "JTAG_DBP_CPU0_QS_GTL_R_TMS")
	)
	(arc
		(start 333.923132 -223.251268)
		(mid 334.205834 -223.32701)
		(end 334.488536 -223.251268)
		(width 0.0889)
		(layer "B.Cu")
		(net "JTAG_DBP_CPU0_QS_GTL_R_TMS")
	)
	(arc
		(start 342.946736 -223.251268)
		(mid 343.133934 -223.201125)
		(end 343.321132 -223.251268)
		(width 0.0889)
		(layer "B.Cu")
		(net "JTAG_DBP_CPU0_QS_GTL_R_TMS")
	)
	(arc
		(start 337.307936 -223.251268)
		(mid 337.495134 -223.201125)
		(end 337.682332 -223.251268)
		(width 0.0889)
		(layer "B.Cu")
		(net "JTAG_DBP_CPU0_QS_GTL_R_TMS")
	)
	(arc
		(start 355.547168 -229.767384)
		(mid 355.678082 -229.903744)
		(end 355.72573 -230.086662)
		(width 0.0889)
		(layer "B.Cu")
		(net "JTAG_DBP_CPU0_QS_GTL_R_TMS")
	)
	(arc
		(start 355.256084 -229.28834)
		(mid 355.335454 -229.562074)
		(end 355.538278 -229.762304)
		(width 0.0889)
		(layer "B.Cu")
		(net "JTAG_DBP_CPU0_QS_GTL_R_TMS")
	)
	(arc
		(start 354.137722 -227.325682)
		(mid 354.268636 -227.462042)
		(end 354.316284 -227.64496)
		(width 0.0889)
		(layer "B.Cu")
		(net "JTAG_DBP_CPU0_QS_GTL_R_TMS")
	)
	(arc
		(start 337.682332 -223.251268)
		(mid 337.958891 -223.326977)
		(end 338.237068 -223.257364)
		(width 0.0889)
		(layer "B.Cu")
		(net "JTAG_DBP_CPU0_QS_GTL_R_TMS")
	)
	(arc
		(start 355.72573 -230.102156)
		(mid 356.015074 -230.580186)
		(end 356.573836 -230.57612)
		(width 0.0889)
		(layer "B.Cu")
		(net "JTAG_DBP_CPU0_QS_GTL_R_TMS")
	)
	(arc
		(start 353.84613 -226.831144)
		(mid 353.918365 -227.107668)
		(end 354.11664 -227.31349)
		(width 0.0889)
		(layer "B.Cu")
		(net "JTAG_DBP_CPU0_QS_GTL_R_TMS")
	)
	(arc
		(start 353.376484 -226.032822)
		(mid 353.455854 -226.306556)
		(end 353.658678 -226.506786)
		(width 0.0889)
		(layer "B.Cu")
		(net "JTAG_DBP_CPU0_QS_GTL_R_TMS")
	)
	(arc
		(start 346.705936 -223.251268)
		(mid 346.893134 -223.201125)
		(end 347.080332 -223.251268)
		(width 0.0889)
		(layer "B.Cu")
		(net "JTAG_DBP_CPU0_QS_GTL_R_TMS")
	)
	(arc
		(start 340.501478 -223.251268)
		(mid 340.778291 -223.327104)
		(end 341.056722 -223.257364)
		(width 0.0889)
		(layer "B.Cu")
		(net "JTAG_DBP_CPU0_QS_GTL_R_TMS")
	)
	(arc
		(start 348.959932 -223.251268)
		(mid 349.236491 -223.326977)
		(end 349.514668 -223.257364)
		(width 0.0889)
		(layer "B.Cu")
		(net "JTAG_DBP_CPU0_QS_GTL_R_TMS")
	)
	(arc
		(start 350.465136 -223.251268)
		(mid 350.652334 -223.201125)
		(end 350.839532 -223.251268)
		(width 0.0889)
		(layer "B.Cu")
		(net "JTAG_DBP_CPU0_QS_GTL_R_TMS")
	)
	(arc
		(start 342.006682 -223.251268)
		(mid 342.19388 -223.201125)
		(end 342.381078 -223.251268)
		(width 0.0889)
		(layer "B.Cu")
		(net "JTAG_DBP_CPU0_QS_GTL_R_TMS")
	)
	(arc
		(start 351.404682 -223.251268)
		(mid 351.779157 -223.251314)
		(end 351.96653 -223.575626)
		(width 0.0889)
		(layer "B.Cu")
		(net "JTAG_DBP_CPU0_QS_GTL_R_TMS")
	)
	(arc
		(start 352.436684 -224.404936)
		(mid 352.516054 -224.67867)
		(end 352.718878 -224.8789)
		(width 0.0889)
		(layer "B.Cu")
		(net "JTAG_DBP_CPU0_QS_GTL_R_TMS")
	)
	(arc
		(start 334.488536 -223.251268)
		(mid 334.675734 -223.201125)
		(end 334.862932 -223.251268)
		(width 0.0889)
		(layer "B.Cu")
		(net "JTAG_DBP_CPU0_QS_GTL_R_TMS")
	)
	(arc
		(start 340.127082 -223.251268)
		(mid 340.31428 -223.201125)
		(end 340.501478 -223.251268)
		(width 0.0889)
		(layer "B.Cu")
		(net "JTAG_DBP_CPU0_QS_GTL_R_TMS")
	)
	(arc
		(start 345.200732 -223.251268)
		(mid 345.477291 -223.326977)
		(end 345.755468 -223.257364)
		(width 0.0889)
		(layer "B.Cu")
		(net "JTAG_DBP_CPU0_QS_GTL_R_TMS")
	)
	(arc
		(start 353.197922 -225.69805)
		(mid 353.328836 -225.83441)
		(end 353.376484 -226.017328)
		(width 0.0889)
		(layer "B.Cu")
		(net "JTAG_DBP_CPU0_QS_GTL_R_TMS")
	)
	(arc
		(start 341.441532 -223.251268)
		(mid 341.718091 -223.326977)
		(end 341.996268 -223.257364)
		(width 0.0889)
		(layer "B.Cu")
		(net "JTAG_DBP_CPU0_QS_GTL_R_TMS")
	)
	(arc
		(start 348.019878 -223.251268)
		(mid 348.296691 -223.327104)
		(end 348.575122 -223.257364)
		(width 0.0889)
		(layer "B.Cu")
		(net "JTAG_DBP_CPU0_QS_GTL_R_TMS")
	)
	(arc
		(start 347.080332 -223.251268)
		(mid 347.356891 -223.326977)
		(end 347.635068 -223.257364)
		(width 0.0889)
		(layer "B.Cu")
		(net "JTAG_DBP_CPU0_QS_GTL_R_TMS")
	)
	(arc
		(start 351.96653 -223.575626)
		(mid 352.038765 -223.85215)
		(end 352.23704 -224.057972)
		(width 0.0889)
		(layer "B.Cu")
		(net "JTAG_DBP_CPU0_QS_GTL_R_TMS")
	)
	(arc
		(start 346.140278 -223.251268)
		(mid 346.417091 -223.327104)
		(end 346.695522 -223.257364)
		(width 0.0889)
		(layer "B.Cu")
		(net "JTAG_DBP_CPU0_QS_GTL_R_TMS")
	)
	(arc
		(start 338.621878 -223.251268)
		(mid 338.898691 -223.327104)
		(end 339.177122 -223.257364)
		(width 0.0889)
		(layer "B.Cu")
		(net "JTAG_DBP_CPU0_QS_GTL_R_TMS")
	)
	(arc
		(start 356.573836 -230.57612)
		(mid 356.944559 -230.574028)
		(end 357.13543 -230.891842)
		(width 0.0889)
		(layer "B.Cu")
		(net "JTAG_DBP_CPU0_QS_GTL_R_TMS")
	)
	(arc
		(start 357.13543 -230.922576)
		(mid 357.216421 -231.192765)
		(end 357.417878 -231.39019)
		(width 0.0889)
		(layer "B.Cu")
		(net "JTAG_DBP_CPU0_QS_GTL_R_TMS")
	)
	(arc
		(start 357.426768 -231.39527)
		(mid 357.557682 -231.53163)
		(end 357.60533 -231.714548)
		(width 0.0889)
		(layer "B.Cu")
		(net "JTAG_DBP_CPU0_QS_GTL_R_TMS")
	)
	(arc
		(start 355.077522 -228.953568)
		(mid 355.208436 -229.089928)
		(end 355.256084 -229.272846)
		(width 0.0889)
		(layer "B.Cu")
		(net "JTAG_DBP_CPU0_QS_GTL_R_TMS")
	)
	(arc
		(start 339.561932 -223.251268)
		(mid 339.838491 -223.326977)
		(end 340.116668 -223.257364)
		(width 0.0889)
		(layer "B.Cu")
		(net "JTAG_DBP_CPU0_QS_GTL_R_TMS")
	)
	(arc
		(start 354.316284 -227.667058)
		(mid 354.397195 -227.937186)
		(end 354.598478 -228.134672)
		(width 0.0889)
		(layer "B.Cu")
		(net "JTAG_DBP_CPU0_QS_GTL_R_TMS")
	)
	(arc
		(start 348.585536 -223.251268)
		(mid 348.772734 -223.201125)
		(end 348.959932 -223.251268)
		(width 0.0889)
		(layer "B.Cu")
		(net "JTAG_DBP_CPU0_QS_GTL_R_TMS")
	)
	(arc
		(start 333.548736 -223.251268)
		(mid 333.735934 -223.201125)
		(end 333.923132 -223.251268)
		(width 0.0889)
		(layer "B.Cu")
		(net "JTAG_DBP_CPU0_QS_GTL_R_TMS")
	)
	(arc
		(start 335.802732 -223.251268)
		(mid 336.076961 -223.327193)
		(end 336.353404 -223.259904)
		(width 0.0889)
		(layer "B.Cu")
		(net "JTAG_DBP_CPU0_QS_GTL_R_TMS")
	)
	(arc
		(start 349.899478 -223.251268)
		(mid 350.176291 -223.327104)
		(end 350.454722 -223.257364)
		(width 0.0889)
		(layer "B.Cu")
		(net "JTAG_DBP_CPU0_QS_GTL_R_TMS")
	)
	(arc
		(start 352.727768 -224.88398)
		(mid 352.858682 -225.02034)
		(end 352.90633 -225.203258)
		(width 0.0889)
		(layer "B.Cu")
		(net "JTAG_DBP_CPU0_QS_GTL_R_TMS")
	)
	(arc
		(start 347.645482 -223.251268)
		(mid 347.83268 -223.201125)
		(end 348.019878 -223.251268)
		(width 0.0889)
		(layer "B.Cu")
		(net "JTAG_DBP_CPU0_QS_GTL_R_TMS")
	)
	(arc
		(start 333.290418 -223.327722)
		(mid 333.407686 -223.310257)
		(end 333.518764 -223.268794)
		(width 0.0889)
		(layer "B.Cu")
		(net "JTAG_DBP_CPU0_QS_GTL_R_TMS")
	)
	(arc
		(start 344.826336 -223.251268)
		(mid 345.013534 -223.201125)
		(end 345.200732 -223.251268)
		(width 0.0889)
		(layer "B.Cu")
		(net "JTAG_DBP_CPU0_QS_GTL_R_TMS")
	)
	(arc
		(start 336.376518 -223.246442)
		(mid 336.560026 -223.201164)
		(end 336.742278 -223.251268)
		(width 0.0889)
		(layer "B.Cu")
		(net "JTAG_DBP_CPU0_QS_GTL_R_TMS")
	)
	(arc
		(start 335.428336 -223.251268)
		(mid 335.615534 -223.201125)
		(end 335.802732 -223.251268)
		(width 0.0889)
		(layer "B.Cu")
		(net "JTAG_DBP_CPU0_QS_GTL_R_TMS")
	)
	(arc
		(start 343.321132 -223.251268)
		(mid 343.597691 -223.326977)
		(end 343.875868 -223.257364)
		(width 0.0889)
		(layer "B.Cu")
		(net "JTAG_DBP_CPU0_QS_GTL_R_TMS")
	)
	(arc
		(start 339.187536 -223.251268)
		(mid 339.374734 -223.201125)
		(end 339.561932 -223.251268)
		(width 0.0889)
		(layer "B.Cu")
		(net "JTAG_DBP_CPU0_QS_GTL_R_TMS")
	)
	(arc
		(start 343.886282 -223.251268)
		(mid 344.07348 -223.201125)
		(end 344.260678 -223.251268)
		(width 0.0889)
		(layer "B.Cu")
		(net "JTAG_DBP_CPU0_QS_GTL_R_TMS")
	)
	(arc
		(start 349.525082 -223.251268)
		(mid 349.71228 -223.201125)
		(end 349.899478 -223.251268)
		(width 0.0889)
		(layer "B.Cu")
		(net "JTAG_DBP_CPU0_QS_GTL_R_TMS")
	)
	(arc
		(start 352.258122 -224.070164)
		(mid 352.389036 -224.206524)
		(end 352.436684 -224.389442)
		(width 0.0889)
		(layer "B.Cu")
		(net "JTAG_DBP_CPU0_QS_GTL_R_TMS")
	)
	(arc
		(start 354.78593 -228.45903)
		(mid 354.859921 -228.738596)
		(end 355.062536 -228.944932)
		(width 0.0889)
		(layer "B.Cu")
		(net "JTAG_DBP_CPU0_QS_GTL_R_TMS")
	)
	(arc
		(start 354.607368 -228.139752)
		(mid 354.738282 -228.276112)
		(end 354.78593 -228.45903)
		(width 0.0889)
		(layer "B.Cu")
		(net "JTAG_DBP_CPU0_QS_GTL_R_TMS")
	)
	(arc
		(start 345.765882 -223.251268)
		(mid 345.95308 -223.201125)
		(end 346.140278 -223.251268)
		(width 0.0889)
		(layer "B.Cu")
		(net "JTAG_DBP_CPU0_QS_GTL_R_TMS")
	)
	(arc
		(start 350.839532 -223.251268)
		(mid 351.116091 -223.326977)
		(end 351.394268 -223.257364)
		(width 0.0889)
		(layer "B.Cu")
		(net "JTAG_DBP_CPU0_QS_GTL_R_TMS")
	)
	(arc
		(start 336.742278 -223.251268)
		(mid 337.019091 -223.327104)
		(end 337.297522 -223.257364)
		(width 0.0889)
		(layer "B.Cu")
		(net "JTAG_DBP_CPU0_QS_GTL_R_TMS")
	)
	(arc
		(start 342.381078 -223.251268)
		(mid 342.657891 -223.327104)
		(end 342.936322 -223.257364)
		(width 0.0889)
		(layer "B.Cu")
		(net "JTAG_DBP_CPU0_QS_GTL_R_TMS")
	)
	(arc
		(start 341.067136 -223.251268)
		(mid 341.254334 -223.201125)
		(end 341.441532 -223.251268)
		(width 0.0889)
		(layer "B.Cu")
		(net "JTAG_DBP_CPU0_QS_GTL_R_TMS")
	)
	(arc
		(start 353.667568 -226.511866)
		(mid 353.798482 -226.648226)
		(end 353.84613 -226.831144)
		(width 0.0889)
		(layer "B.Cu")
		(net "JTAG_DBP_CPU0_QS_GTL_R_TMS")
	)
	(arc
		(start 334.862932 -223.251268)
		(mid 335.145634 -223.32701)
		(end 335.428336 -223.251268)
		(width 0.0889)
		(layer "B.Cu")
		(net "JTAG_DBP_CPU0_QS_GTL_R_TMS")
	)
	(arc
		(start 352.90633 -225.217482)
		(mid 352.985549 -225.492167)
		(end 353.189032 -225.69297)
		(width 0.0889)
		(layer "B.Cu")
		(net "JTAG_DBP_CPU0_QS_GTL_R_TMS")
	)
	(segment
		(start 359.580434 -233.06405)
		(end 359.580434 -232.528364)
		(width 0.12954)
		(layer "F.Cu")
		(net "JTAG_DBP_CPU0_GTL_R_TDI")
	)
	(segment
		(start 359.58018 -233.064304)
		(end 359.580434 -233.06405)
		(width 0.12954)
		(layer "F.Cu")
		(net "JTAG_DBP_CPU0_GTL_R_TDI")
	)
	(via
		(at 359.580434 -232.528364)
		(size 0.4572)
		(drill 0.2032)
		(layers "F.Cu" "B.Cu")
		(net "JTAG_DBP_CPU0_GTL_R_TDI")
	)
	(via
		(at 337.359498 -196.788278)
		(size 0.7112)
		(drill 0.3556)
		(layers "F.Cu" "B.Cu")
		(net "JTAG_DBP_CPU0_GTL_R_TDI")
	)
	(segment
		(start 356.573836 -227.320602)
		(end 356.564946 -227.325682)
		(width 0.0889)
		(layer "B.Cu")
		(net "JTAG_DBP_CPU0_GTL_R_TDI")
	)
	(segment
		(start 337.359498 -191.721232)
		(end 337.359498 -196.788278)
		(width 0.12954)
		(layer "B.Cu")
		(net "JTAG_DBP_CPU0_GTL_R_TDI")
	)
	(segment
		(start 358.444546 -229.592124)
		(end 358.453436 -229.597204)
		(width 0.0889)
		(layer "B.Cu")
		(net "JTAG_DBP_CPU0_GTL_R_TDI")
	)
	(segment
		(start 359.297478 -231.39019)
		(end 359.297986 -231.390698)
		(width 0.0889)
		(layer "B.Cu")
		(net "JTAG_DBP_CPU0_GTL_R_TDI")
	)
	(segment
		(start 338.911692 -189.044072)
		(end 338.793074 -189.16269)
		(width 0.12954)
		(layer "B.Cu")
		(net "JTAG_DBP_CPU0_GTL_R_TDI")
	)
	(segment
		(start 359.485184 -231.748076)
		(end 359.580434 -232.528364)
		(width 0.0889)
		(layer "B.Cu")
		(net "JTAG_DBP_CPU0_GTL_R_TDI")
	)
	(segment
		(start 355.634036 -224.065084)
		(end 355.625146 -224.070164)
		(width 0.0889)
		(layer "B.Cu")
		(net "JTAG_DBP_CPU0_GTL_R_TDI")
	)
	(segment
		(start 341.911432 -219.830396)
		(end 341.926164 -219.82176)
		(width 0.0889)
		(layer "B.Cu")
		(net "JTAG_DBP_CPU0_GTL_R_TDI")
	)
	(segment
		(start 355.163882 -222.272098)
		(end 355.169978 -222.275654)
		(width 0.0889)
		(layer "B.Cu")
		(net "JTAG_DBP_CPU0_GTL_R_TDI")
	)
	(segment
		(start 355.625146 -223.080834)
		(end 355.634036 -223.085914)
		(width 0.0889)
		(layer "B.Cu")
		(net "JTAG_DBP_CPU0_GTL_R_TDI")
	)
	(segment
		(start 335.419192 -217.383614)
		(end 335.428082 -217.388694)
		(width 0.0889)
		(layer "B.Cu")
		(net "JTAG_DBP_CPU0_GTL_R_TDI")
	)
	(segment
		(start 338.152232 -219.830396)
		(end 338.166964 -219.82176)
		(width 0.0889)
		(layer "B.Cu")
		(net "JTAG_DBP_CPU0_GTL_R_TDI")
	)
	(segment
		(start 337.359498 -199.777096)
		(end 332.952344 -204.18425)
		(width 0.12954)
		(layer "B.Cu")
		(net "JTAG_DBP_CPU0_GTL_R_TDI")
	)
	(segment
		(start 340.031832 -219.830396)
		(end 340.046564 -219.82176)
		(width 0.0889)
		(layer "B.Cu")
		(net "JTAG_DBP_CPU0_GTL_R_TDI")
	)
	(segment
		(start 351.309432 -219.830396)
		(end 351.324164 -219.82176)
		(width 0.0889)
		(layer "B.Cu")
		(net "JTAG_DBP_CPU0_GTL_R_TDI")
	)
	(segment
		(start 355.14915 -222.263462)
		(end 355.163882 -222.272098)
		(width 0.0889)
		(layer "B.Cu")
		(net "JTAG_DBP_CPU0_GTL_R_TDI")
	)
	(segment
		(start 355.625146 -224.70872)
		(end 355.634036 -224.7138)
		(width 0.0889)
		(layer "B.Cu")
		(net "JTAG_DBP_CPU0_GTL_R_TDI")
	)
	(segment
		(start 356.564946 -227.964238)
		(end 356.573836 -227.969318)
		(width 0.0889)
		(layer "B.Cu")
		(net "JTAG_DBP_CPU0_GTL_R_TDI")
	)
	(segment
		(start 338.793074 -189.16269)
		(end 337.344004 -189.16269)
		(width 0.12954)
		(layer "B.Cu")
		(net "JTAG_DBP_CPU0_GTL_R_TDI")
	)
	(segment
		(start 356.386384 -226.003104)
		(end 356.386384 -226.017328)
		(width 0.0889)
		(layer "B.Cu")
		(net "JTAG_DBP_CPU0_GTL_R_TDI")
	)
	(segment
		(start 334.402938 -214.86495)
		(end 334.402938 -215.30945)
		(width 0.12954)
		(layer "B.Cu")
		(net "JTAG_DBP_CPU0_GTL_R_TDI")
	)
	(segment
		(start 357.974392 -228.778308)
		(end 357.983282 -228.783388)
		(width 0.0889)
		(layer "B.Cu")
		(net "JTAG_DBP_CPU0_GTL_R_TDI")
	)
	(segment
		(start 338.911692 -188.398658)
		(end 338.911692 -189.044072)
		(width 0.12954)
		(layer "B.Cu")
		(net "JTAG_DBP_CPU0_GTL_R_TDI")
	)
	(segment
		(start 336.79257 -191.154304)
		(end 337.359498 -191.721232)
		(width 0.12954)
		(layer "B.Cu")
		(net "JTAG_DBP_CPU0_GTL_R_TDI")
	)
	(segment
		(start 349.429832 -219.830396)
		(end 349.444564 -219.82176)
		(width 0.0889)
		(layer "B.Cu")
		(net "JTAG_DBP_CPU0_GTL_R_TDI")
	)
	(segment
		(start 356.094792 -225.522536)
		(end 356.103682 -225.527616)
		(width 0.0889)
		(layer "B.Cu")
		(net "JTAG_DBP_CPU0_GTL_R_TDI")
	)
	(segment
		(start 353.745546 -221.453202)
		(end 353.754436 -221.458282)
		(width 0.0889)
		(layer "B.Cu")
		(net "JTAG_DBP_CPU0_GTL_R_TDI")
	)
	(segment
		(start 336.829146 -219.825316)
		(end 336.838036 -219.830396)
		(width 0.0889)
		(layer "B.Cu")
		(net "JTAG_DBP_CPU0_GTL_R_TDI")
	)
	(segment
		(start 351.874836 -219.830396)
		(end 351.880932 -219.833952)
		(width 0.0889)
		(layer "B.Cu")
		(net "JTAG_DBP_CPU0_GTL_R_TDI")
	)
	(segment
		(start 357.983282 -228.783388)
		(end 357.989378 -228.786944)
		(width 0.0889)
		(layer "B.Cu")
		(net "JTAG_DBP_CPU0_GTL_R_TDI")
	)
	(segment
		(start 358.453436 -229.597204)
		(end 358.459532 -229.60076)
		(width 0.0889)
		(layer "B.Cu")
		(net "JTAG_DBP_CPU0_GTL_R_TDI")
	)
	(segment
		(start 359.485184 -231.714548)
		(end 359.485184 -231.748076)
		(width 0.0889)
		(layer "B.Cu")
		(net "JTAG_DBP_CPU0_GTL_R_TDI")
	)
	(segment
		(start 334.77073 -215.677242)
		(end 334.77073 -216.11209)
		(width 0.12954)
		(layer "B.Cu")
		(net "JTAG_DBP_CPU0_GTL_R_TDI")
	)
	(segment
		(start 353.273868 -220.638116)
		(end 353.284282 -220.644212)
		(width 0.0889)
		(layer "B.Cu")
		(net "JTAG_DBP_CPU0_GTL_R_TDI")
	)
	(segment
		(start 335.71053 -217.864182)
		(end 335.71053 -217.878406)
		(width 0.0889)
		(layer "B.Cu")
		(net "JTAG_DBP_CPU0_GTL_R_TDI")
	)
	(segment
		(start 336.359246 -219.0115)
		(end 336.368136 -219.01658)
		(width 0.0889)
		(layer "B.Cu")
		(net "JTAG_DBP_CPU0_GTL_R_TDI")
	)
	(segment
		(start 355.640132 -224.061528)
		(end 355.634036 -224.065084)
		(width 0.0889)
		(layer "B.Cu")
		(net "JTAG_DBP_CPU0_GTL_R_TDI")
	)
	(segment
		(start 355.91623 -225.187764)
		(end 355.91623 -225.203258)
		(width 0.0889)
		(layer "B.Cu")
		(net "JTAG_DBP_CPU0_GTL_R_TDI")
	)
	(segment
		(start 352.335846 -220.639132)
		(end 352.344736 -220.644212)
		(width 0.0889)
		(layer "B.Cu")
		(net "JTAG_DBP_CPU0_GTL_R_TDI")
	)
	(segment
		(start 337.344004 -189.16269)
		(end 336.79257 -189.714124)
		(width 0.12954)
		(layer "B.Cu")
		(net "JTAG_DBP_CPU0_GTL_R_TDI")
	)
	(segment
		(start 347.550232 -219.830396)
		(end 347.564964 -219.82176)
		(width 0.0889)
		(layer "B.Cu")
		(net "JTAG_DBP_CPU0_GTL_R_TDI")
	)
	(segment
		(start 359.015284 -230.506778)
		(end 359.015284 -230.922576)
		(width 0.0889)
		(layer "B.Cu")
		(net "JTAG_DBP_CPU0_GTL_R_TDI")
	)
	(segment
		(start 356.564946 -226.336606)
		(end 356.573836 -226.341686)
		(width 0.0889)
		(layer "B.Cu")
		(net "JTAG_DBP_CPU0_GTL_R_TDI")
	)
	(segment
		(start 334.957928 -216.574878)
		(end 334.964024 -216.578434)
		(width 0.0889)
		(layer "B.Cu")
		(net "JTAG_DBP_CPU0_GTL_R_TDI")
	)
	(segment
		(start 343.791032 -219.830396)
		(end 343.805764 -219.82176)
		(width 0.0889)
		(layer "B.Cu")
		(net "JTAG_DBP_CPU0_GTL_R_TDI")
	)
	(segment
		(start 337.359498 -196.788278)
		(end 337.359498 -199.777096)
		(width 0.12954)
		(layer "B.Cu")
		(net "JTAG_DBP_CPU0_GTL_R_TDI")
	)
	(segment
		(start 336.650584 -219.496132)
		(end 336.650584 -219.506038)
		(width 0.0889)
		(layer "B.Cu")
		(net "JTAG_DBP_CPU0_GTL_R_TDI")
	)
	(segment
		(start 332.952344 -204.18425)
		(end 332.952344 -213.414356)
		(width 0.12954)
		(layer "B.Cu")
		(net "JTAG_DBP_CPU0_GTL_R_TDI")
	)
	(segment
		(start 345.670632 -219.830396)
		(end 345.685364 -219.82176)
		(width 0.0889)
		(layer "B.Cu")
		(net "JTAG_DBP_CPU0_GTL_R_TDI")
	)
	(segment
		(start 357.79583 -228.436932)
		(end 357.79583 -228.45903)
		(width 0.0889)
		(layer "B.Cu")
		(net "JTAG_DBP_CPU0_GTL_R_TDI")
	)
	(segment
		(start 336.79257 -189.714124)
		(end 336.79257 -191.154304)
		(width 0.12954)
		(layer "B.Cu")
		(net "JTAG_DBP_CPU0_GTL_R_TDI")
	)
	(segment
		(start 334.402938 -215.30945)
		(end 334.77073 -215.677242)
		(width 0.12954)
		(layer "B.Cu")
		(net "JTAG_DBP_CPU0_GTL_R_TDI")
	)
	(segment
		(start 355.916484 -223.561402)
		(end 355.916484 -223.575626)
		(width 0.0889)
		(layer "B.Cu")
		(net "JTAG_DBP_CPU0_GTL_R_TDI")
	)
	(segment
		(start 354.03663 -221.932246)
		(end 354.03663 -221.94774)
		(width 0.0889)
		(layer "B.Cu")
		(net "JTAG_DBP_CPU0_GTL_R_TDI")
	)
	(segment
		(start 336.180684 -218.682316)
		(end 336.180684 -218.692222)
		(width 0.0889)
		(layer "B.Cu")
		(net "JTAG_DBP_CPU0_GTL_R_TDI")
	)
	(segment
		(start 334.77073 -216.11209)
		(end 334.77073 -216.259156)
		(width 0.0889)
		(layer "B.Cu")
		(net "JTAG_DBP_CPU0_GTL_R_TDI")
	)
	(segment
		(start 358.914446 -230.40594)
		(end 359.015284 -230.506778)
		(width 0.0889)
		(layer "B.Cu")
		(net "JTAG_DBP_CPU0_GTL_R_TDI")
	)
	(segment
		(start 356.856284 -226.821238)
		(end 356.856284 -226.84105)
		(width 0.0889)
		(layer "B.Cu")
		(net "JTAG_DBP_CPU0_GTL_R_TDI")
	)
	(segment
		(start 353.566984 -221.1197)
		(end 353.566984 -221.133924)
		(width 0.0889)
		(layer "B.Cu")
		(net "JTAG_DBP_CPU0_GTL_R_TDI")
	)
	(segment
		(start 356.948232 -227.969318)
		(end 356.962964 -227.960682)
		(width 0.0889)
		(layer "B.Cu")
		(net "JTAG_DBP_CPU0_GTL_R_TDI")
	)
	(segment
		(start 332.952344 -213.414356)
		(end 334.402938 -214.86495)
		(width 0.12954)
		(layer "B.Cu")
		(net "JTAG_DBP_CPU0_GTL_R_TDI")
	)
	(segment
		(start 335.88325 -218.194128)
		(end 335.898236 -218.202764)
		(width 0.0889)
		(layer "B.Cu")
		(net "JTAG_DBP_CPU0_GTL_R_TDI")
	)
	(segment
		(start 354.215192 -222.267018)
		(end 354.224082 -222.272098)
		(width 0.0889)
		(layer "B.Cu")
		(net "JTAG_DBP_CPU0_GTL_R_TDI")
	)
	(arc
		(start 343.416636 -219.830396)
		(mid 343.603834 -219.880539)
		(end 343.791032 -219.830396)
		(width 0.0889)
		(layer "B.Cu")
		(net "JTAG_DBP_CPU0_GTL_R_TDI")
	)
	(arc
		(start 346.610432 -219.830396)
		(mid 346.893134 -219.75462)
		(end 347.175836 -219.830396)
		(width 0.0889)
		(layer "B.Cu")
		(net "JTAG_DBP_CPU0_GTL_R_TDI")
	)
	(arc
		(start 347.175836 -219.830396)
		(mid 347.363034 -219.880539)
		(end 347.550232 -219.830396)
		(width 0.0889)
		(layer "B.Cu")
		(net "JTAG_DBP_CPU0_GTL_R_TDI")
	)
	(arc
		(start 355.169978 -222.275654)
		(mid 355.372565 -222.482005)
		(end 355.446584 -222.761556)
		(width 0.0889)
		(layer "B.Cu")
		(net "JTAG_DBP_CPU0_GTL_R_TDI")
	)
	(arc
		(start 355.634036 -223.085914)
		(mid 355.837341 -223.28678)
		(end 355.916484 -223.561402)
		(width 0.0889)
		(layer "B.Cu")
		(net "JTAG_DBP_CPU0_GTL_R_TDI")
	)
	(arc
		(start 351.880932 -219.833952)
		(mid 352.083345 -220.040365)
		(end 352.157284 -220.319854)
		(width 0.0889)
		(layer "B.Cu")
		(net "JTAG_DBP_CPU0_GTL_R_TDI")
	)
	(arc
		(start 358.459532 -229.60076)
		(mid 358.661945 -229.807173)
		(end 358.735884 -230.086662)
		(width 0.0889)
		(layer "B.Cu")
		(net "JTAG_DBP_CPU0_GTL_R_TDI")
	)
	(arc
		(start 357.989378 -228.786944)
		(mid 358.191965 -228.993295)
		(end 358.265984 -229.272846)
		(width 0.0889)
		(layer "B.Cu")
		(net "JTAG_DBP_CPU0_GTL_R_TDI")
	)
	(arc
		(start 354.224082 -222.272098)
		(mid 354.41128 -222.322241)
		(end 354.598478 -222.272098)
		(width 0.0889)
		(layer "B.Cu")
		(net "JTAG_DBP_CPU0_GTL_R_TDI")
	)
	(arc
		(start 338.166964 -219.82176)
		(mid 338.443439 -219.75444)
		(end 338.717636 -219.830396)
		(width 0.0889)
		(layer "B.Cu")
		(net "JTAG_DBP_CPU0_GTL_R_TDI")
	)
	(arc
		(start 350.369632 -219.830396)
		(mid 350.652334 -219.75462)
		(end 350.935036 -219.830396)
		(width 0.0889)
		(layer "B.Cu")
		(net "JTAG_DBP_CPU0_GTL_R_TDI")
	)
	(arc
		(start 335.428082 -217.388694)
		(mid 335.631387 -217.58956)
		(end 335.71053 -217.864182)
		(width 0.0889)
		(layer "B.Cu")
		(net "JTAG_DBP_CPU0_GTL_R_TDI")
	)
	(arc
		(start 334.77073 -216.259156)
		(mid 334.823 -216.441521)
		(end 334.957928 -216.574878)
		(width 0.0889)
		(layer "B.Cu")
		(net "JTAG_DBP_CPU0_GTL_R_TDI")
	)
	(arc
		(start 342.851232 -219.830396)
		(mid 343.133934 -219.75462)
		(end 343.416636 -219.830396)
		(width 0.0889)
		(layer "B.Cu")
		(net "JTAG_DBP_CPU0_GTL_R_TDI")
	)
	(arc
		(start 336.368136 -219.01658)
		(mid 336.572471 -219.219185)
		(end 336.650584 -219.496132)
		(width 0.0889)
		(layer "B.Cu")
		(net "JTAG_DBP_CPU0_GTL_R_TDI")
	)
	(arc
		(start 346.236036 -219.830396)
		(mid 346.423234 -219.880539)
		(end 346.610432 -219.830396)
		(width 0.0889)
		(layer "B.Cu")
		(net "JTAG_DBP_CPU0_GTL_R_TDI")
	)
	(arc
		(start 341.926164 -219.82176)
		(mid 342.202639 -219.75444)
		(end 342.476836 -219.830396)
		(width 0.0889)
		(layer "B.Cu")
		(net "JTAG_DBP_CPU0_GTL_R_TDI")
	)
	(arc
		(start 336.650584 -219.506038)
		(mid 336.698263 -219.688938)
		(end 336.829146 -219.825316)
		(width 0.0889)
		(layer "B.Cu")
		(net "JTAG_DBP_CPU0_GTL_R_TDI")
	)
	(arc
		(start 335.71053 -217.878406)
		(mid 335.756534 -218.058343)
		(end 335.88325 -218.194128)
		(width 0.0889)
		(layer "B.Cu")
		(net "JTAG_DBP_CPU0_GTL_R_TDI")
	)
	(arc
		(start 342.476836 -219.830396)
		(mid 342.664034 -219.880539)
		(end 342.851232 -219.830396)
		(width 0.0889)
		(layer "B.Cu")
		(net "JTAG_DBP_CPU0_GTL_R_TDI")
	)
	(arc
		(start 352.344736 -220.644212)
		(mid 352.531934 -220.694355)
		(end 352.719132 -220.644212)
		(width 0.0889)
		(layer "B.Cu")
		(net "JTAG_DBP_CPU0_GTL_R_TDI")
	)
	(arc
		(start 353.754436 -221.458282)
		(mid 353.957259 -221.658513)
		(end 354.03663 -221.932246)
		(width 0.0889)
		(layer "B.Cu")
		(net "JTAG_DBP_CPU0_GTL_R_TDI")
	)
	(arc
		(start 351.324164 -219.82176)
		(mid 351.600639 -219.75444)
		(end 351.874836 -219.830396)
		(width 0.0889)
		(layer "B.Cu")
		(net "JTAG_DBP_CPU0_GTL_R_TDI")
	)
	(arc
		(start 337.212432 -219.830396)
		(mid 337.495134 -219.75462)
		(end 337.777836 -219.830396)
		(width 0.0889)
		(layer "B.Cu")
		(net "JTAG_DBP_CPU0_GTL_R_TDI")
	)
	(arc
		(start 359.015284 -230.922576)
		(mid 359.096195 -231.192704)
		(end 359.297478 -231.39019)
		(width 0.0889)
		(layer "B.Cu")
		(net "JTAG_DBP_CPU0_GTL_R_TDI")
	)
	(arc
		(start 349.995236 -219.830396)
		(mid 350.182434 -219.880539)
		(end 350.369632 -219.830396)
		(width 0.0889)
		(layer "B.Cu")
		(net "JTAG_DBP_CPU0_GTL_R_TDI")
	)
	(arc
		(start 347.564964 -219.82176)
		(mid 347.841439 -219.75444)
		(end 348.115636 -219.830396)
		(width 0.0889)
		(layer "B.Cu")
		(net "JTAG_DBP_CPU0_GTL_R_TDI")
	)
	(arc
		(start 359.297986 -231.390698)
		(mid 359.434967 -231.527548)
		(end 359.485184 -231.714548)
		(width 0.0889)
		(layer "B.Cu")
		(net "JTAG_DBP_CPU0_GTL_R_TDI")
	)
	(arc
		(start 354.598478 -222.272098)
		(mid 354.872677 -222.196263)
		(end 355.14915 -222.263462)
		(width 0.0889)
		(layer "B.Cu")
		(net "JTAG_DBP_CPU0_GTL_R_TDI")
	)
	(arc
		(start 338.717636 -219.830396)
		(mid 338.904834 -219.880539)
		(end 339.092032 -219.830396)
		(width 0.0889)
		(layer "B.Cu")
		(net "JTAG_DBP_CPU0_GTL_R_TDI")
	)
	(arc
		(start 356.103682 -225.527616)
		(mid 356.307163 -225.72842)
		(end 356.386384 -226.003104)
		(width 0.0889)
		(layer "B.Cu")
		(net "JTAG_DBP_CPU0_GTL_R_TDI")
	)
	(arc
		(start 340.971632 -219.830396)
		(mid 341.254334 -219.75462)
		(end 341.537036 -219.830396)
		(width 0.0889)
		(layer "B.Cu")
		(net "JTAG_DBP_CPU0_GTL_R_TDI")
	)
	(arc
		(start 356.573836 -227.969318)
		(mid 356.761034 -228.019461)
		(end 356.948232 -227.969318)
		(width 0.0889)
		(layer "B.Cu")
		(net "JTAG_DBP_CPU0_GTL_R_TDI")
	)
	(arc
		(start 349.444564 -219.82176)
		(mid 349.721039 -219.75444)
		(end 349.995236 -219.830396)
		(width 0.0889)
		(layer "B.Cu")
		(net "JTAG_DBP_CPU0_GTL_R_TDI")
	)
	(arc
		(start 341.537036 -219.830396)
		(mid 341.724234 -219.880539)
		(end 341.911432 -219.830396)
		(width 0.0889)
		(layer "B.Cu")
		(net "JTAG_DBP_CPU0_GTL_R_TDI")
	)
	(arc
		(start 355.916484 -223.575626)
		(mid 355.842568 -223.855128)
		(end 355.640132 -224.061528)
		(width 0.0889)
		(layer "B.Cu")
		(net "JTAG_DBP_CPU0_GTL_R_TDI")
	)
	(arc
		(start 352.719132 -220.644212)
		(mid 352.995691 -220.568503)
		(end 353.273868 -220.638116)
		(width 0.0889)
		(layer "B.Cu")
		(net "JTAG_DBP_CPU0_GTL_R_TDI")
	)
	(arc
		(start 348.490032 -219.830396)
		(mid 348.772734 -219.75462)
		(end 349.055436 -219.830396)
		(width 0.0889)
		(layer "B.Cu")
		(net "JTAG_DBP_CPU0_GTL_R_TDI")
	)
	(arc
		(start 345.296236 -219.830396)
		(mid 345.483434 -219.880539)
		(end 345.670632 -219.830396)
		(width 0.0889)
		(layer "B.Cu")
		(net "JTAG_DBP_CPU0_GTL_R_TDI")
	)
	(arc
		(start 356.573836 -226.341686)
		(mid 356.778171 -226.544291)
		(end 356.856284 -226.821238)
		(width 0.0889)
		(layer "B.Cu")
		(net "JTAG_DBP_CPU0_GTL_R_TDI")
	)
	(arc
		(start 339.657436 -219.830396)
		(mid 339.844634 -219.880539)
		(end 340.031832 -219.830396)
		(width 0.0889)
		(layer "B.Cu")
		(net "JTAG_DBP_CPU0_GTL_R_TDI")
	)
	(arc
		(start 344.730832 -219.830396)
		(mid 345.013534 -219.75462)
		(end 345.296236 -219.830396)
		(width 0.0889)
		(layer "B.Cu")
		(net "JTAG_DBP_CPU0_GTL_R_TDI")
	)
	(arc
		(start 358.265984 -229.272846)
		(mid 358.313663 -229.455746)
		(end 358.444546 -229.592124)
		(width 0.0889)
		(layer "B.Cu")
		(net "JTAG_DBP_CPU0_GTL_R_TDI")
	)
	(arc
		(start 357.79583 -228.45903)
		(mid 357.843509 -228.64193)
		(end 357.974392 -228.778308)
		(width 0.0889)
		(layer "B.Cu")
		(net "JTAG_DBP_CPU0_GTL_R_TDI")
	)
	(arc
		(start 349.055436 -219.830396)
		(mid 349.242634 -219.880539)
		(end 349.429832 -219.830396)
		(width 0.0889)
		(layer "B.Cu")
		(net "JTAG_DBP_CPU0_GTL_R_TDI")
	)
	(arc
		(start 350.935036 -219.830396)
		(mid 351.122234 -219.880539)
		(end 351.309432 -219.830396)
		(width 0.0889)
		(layer "B.Cu")
		(net "JTAG_DBP_CPU0_GTL_R_TDI")
	)
	(arc
		(start 335.24063 -217.064336)
		(mid 335.288309 -217.247236)
		(end 335.419192 -217.383614)
		(width 0.0889)
		(layer "B.Cu")
		(net "JTAG_DBP_CPU0_GTL_R_TDI")
	)
	(arc
		(start 345.685364 -219.82176)
		(mid 345.961839 -219.75444)
		(end 346.236036 -219.830396)
		(width 0.0889)
		(layer "B.Cu")
		(net "JTAG_DBP_CPU0_GTL_R_TDI")
	)
	(arc
		(start 343.805764 -219.82176)
		(mid 344.082239 -219.75444)
		(end 344.356436 -219.830396)
		(width 0.0889)
		(layer "B.Cu")
		(net "JTAG_DBP_CPU0_GTL_R_TDI")
	)
	(arc
		(start 339.092032 -219.830396)
		(mid 339.374734 -219.75462)
		(end 339.657436 -219.830396)
		(width 0.0889)
		(layer "B.Cu")
		(net "JTAG_DBP_CPU0_GTL_R_TDI")
	)
	(arc
		(start 336.838036 -219.830396)
		(mid 337.025234 -219.880539)
		(end 337.212432 -219.830396)
		(width 0.0889)
		(layer "B.Cu")
		(net "JTAG_DBP_CPU0_GTL_R_TDI")
	)
	(arc
		(start 356.386384 -226.017328)
		(mid 356.434063 -226.200228)
		(end 356.564946 -226.336606)
		(width 0.0889)
		(layer "B.Cu")
		(net "JTAG_DBP_CPU0_GTL_R_TDI")
	)
	(arc
		(start 340.597236 -219.830396)
		(mid 340.784434 -219.880539)
		(end 340.971632 -219.830396)
		(width 0.0889)
		(layer "B.Cu")
		(net "JTAG_DBP_CPU0_GTL_R_TDI")
	)
	(arc
		(start 335.898236 -218.202764)
		(mid 336.102571 -218.405369)
		(end 336.180684 -218.682316)
		(width 0.0889)
		(layer "B.Cu")
		(net "JTAG_DBP_CPU0_GTL_R_TDI")
	)
	(arc
		(start 358.735884 -230.086662)
		(mid 358.783563 -230.269562)
		(end 358.914446 -230.40594)
		(width 0.0889)
		(layer "B.Cu")
		(net "JTAG_DBP_CPU0_GTL_R_TDI")
	)
	(arc
		(start 355.634036 -224.7138)
		(mid 355.836859 -224.914031)
		(end 355.91623 -225.187764)
		(width 0.0889)
		(layer "B.Cu")
		(net "JTAG_DBP_CPU0_GTL_R_TDI")
	)
	(arc
		(start 352.157284 -220.319854)
		(mid 352.204963 -220.502754)
		(end 352.335846 -220.639132)
		(width 0.0889)
		(layer "B.Cu")
		(net "JTAG_DBP_CPU0_GTL_R_TDI")
	)
	(arc
		(start 334.964024 -216.578434)
		(mid 335.166611 -216.784785)
		(end 335.24063 -217.064336)
		(width 0.0889)
		(layer "B.Cu")
		(net "JTAG_DBP_CPU0_GTL_R_TDI")
	)
	(arc
		(start 357.513636 -227.969318)
		(mid 357.714918 -228.166805)
		(end 357.79583 -228.436932)
		(width 0.0889)
		(layer "B.Cu")
		(net "JTAG_DBP_CPU0_GTL_R_TDI")
	)
	(arc
		(start 356.564946 -227.325682)
		(mid 356.386349 -227.64496)
		(end 356.564946 -227.964238)
		(width 0.0889)
		(layer "B.Cu")
		(net "JTAG_DBP_CPU0_GTL_R_TDI")
	)
	(arc
		(start 355.625146 -224.070164)
		(mid 355.446549 -224.389442)
		(end 355.625146 -224.70872)
		(width 0.0889)
		(layer "B.Cu")
		(net "JTAG_DBP_CPU0_GTL_R_TDI")
	)
	(arc
		(start 344.356436 -219.830396)
		(mid 344.543634 -219.880539)
		(end 344.730832 -219.830396)
		(width 0.0889)
		(layer "B.Cu")
		(net "JTAG_DBP_CPU0_GTL_R_TDI")
	)
	(arc
		(start 355.446584 -222.761556)
		(mid 355.494263 -222.944456)
		(end 355.625146 -223.080834)
		(width 0.0889)
		(layer "B.Cu")
		(net "JTAG_DBP_CPU0_GTL_R_TDI")
	)
	(arc
		(start 356.856284 -226.84105)
		(mid 356.778173 -227.117999)
		(end 356.573836 -227.320602)
		(width 0.0889)
		(layer "B.Cu")
		(net "JTAG_DBP_CPU0_GTL_R_TDI")
	)
	(arc
		(start 337.777836 -219.830396)
		(mid 337.965034 -219.880539)
		(end 338.152232 -219.830396)
		(width 0.0889)
		(layer "B.Cu")
		(net "JTAG_DBP_CPU0_GTL_R_TDI")
	)
	(arc
		(start 355.91623 -225.203258)
		(mid 355.963909 -225.386158)
		(end 356.094792 -225.522536)
		(width 0.0889)
		(layer "B.Cu")
		(net "JTAG_DBP_CPU0_GTL_R_TDI")
	)
	(arc
		(start 356.962964 -227.960682)
		(mid 357.239405 -227.893516)
		(end 357.513636 -227.969318)
		(width 0.0889)
		(layer "B.Cu")
		(net "JTAG_DBP_CPU0_GTL_R_TDI")
	)
	(arc
		(start 336.180684 -218.692222)
		(mid 336.228363 -218.875122)
		(end 336.359246 -219.0115)
		(width 0.0889)
		(layer "B.Cu")
		(net "JTAG_DBP_CPU0_GTL_R_TDI")
	)
	(arc
		(start 348.115636 -219.830396)
		(mid 348.302834 -219.880539)
		(end 348.490032 -219.830396)
		(width 0.0889)
		(layer "B.Cu")
		(net "JTAG_DBP_CPU0_GTL_R_TDI")
	)
	(arc
		(start 354.03663 -221.94774)
		(mid 354.084309 -222.13064)
		(end 354.215192 -222.267018)
		(width 0.0889)
		(layer "B.Cu")
		(net "JTAG_DBP_CPU0_GTL_R_TDI")
	)
	(arc
		(start 340.046564 -219.82176)
		(mid 340.323039 -219.75444)
		(end 340.597236 -219.830396)
		(width 0.0889)
		(layer "B.Cu")
		(net "JTAG_DBP_CPU0_GTL_R_TDI")
	)
	(arc
		(start 353.284282 -220.644212)
		(mid 353.487763 -220.845016)
		(end 353.566984 -221.1197)
		(width 0.0889)
		(layer "B.Cu")
		(net "JTAG_DBP_CPU0_GTL_R_TDI")
	)
	(arc
		(start 353.566984 -221.133924)
		(mid 353.614663 -221.316824)
		(end 353.745546 -221.453202)
		(width 0.0889)
		(layer "B.Cu")
		(net "JTAG_DBP_CPU0_GTL_R_TDI")
	)
	(segment
		(start 358.640888 -232.528618)
		(end 358.640634 -232.528364)
		(width 0.12954)
		(layer "F.Cu")
		(net "JTAG_DBP_CPU0_GTL_R_TCK")
	)
	(segment
		(start 358.640888 -233.06405)
		(end 358.640888 -232.528618)
		(width 0.12954)
		(layer "F.Cu")
		(net "JTAG_DBP_CPU0_GTL_R_TCK")
	)
	(segment
		(start 358.640634 -233.064304)
		(end 358.640888 -233.06405)
		(width 0.12954)
		(layer "F.Cu")
		(net "JTAG_DBP_CPU0_GTL_R_TCK")
	)
	(via
		(at 327.991724 -219.293694)
		(size 0.7112)
		(drill 0.3556)
		(layers "F.Cu" "B.Cu")
		(net "JTAG_DBP_CPU0_GTL_R_TCK")
	)
	(via
		(at 358.640634 -232.528364)
		(size 0.4572)
		(drill 0.2032)
		(layers "F.Cu" "B.Cu")
		(net "JTAG_DBP_CPU0_GTL_R_TCK")
	)
	(segment
		(start 357.504746 -232.847642)
		(end 357.519732 -232.856278)
		(width 0.0889)
		(layer "B.Cu")
		(net "JTAG_DBP_CPU0_GTL_R_TCK")
	)
	(segment
		(start 352.335846 -227.150422)
		(end 352.344736 -227.155502)
		(width 0.0889)
		(layer "B.Cu")
		(net "JTAG_DBP_CPU0_GTL_R_TCK")
	)
	(segment
		(start 354.03663 -228.436932)
		(end 354.03663 -228.45903)
		(width 0.0889)
		(layer "B.Cu")
		(net "JTAG_DBP_CPU0_GTL_R_TCK")
	)
	(segment
		(start 345.858084 -224.389442)
		(end 345.858084 -224.373948)
		(width 0.0889)
		(layer "B.Cu")
		(net "JTAG_DBP_CPU0_GTL_R_TCK")
	)
	(segment
		(start 358.512618 -233.61015)
		(end 358.639618 -233.48315)
		(width 0.0889)
		(layer "B.Cu")
		(net "JTAG_DBP_CPU0_GTL_R_TCK")
	)
	(segment
		(start 339.177122 -223.893888)
		(end 339.187536 -223.899984)
		(width 0.0889)
		(layer "B.Cu")
		(net "JTAG_DBP_CPU0_GTL_R_TCK")
	)
	(segment
		(start 342.098884 -224.389442)
		(end 342.098884 -224.373948)
		(width 0.0889)
		(layer "B.Cu")
		(net "JTAG_DBP_CPU0_GTL_R_TCK")
	)
	(segment
		(start 341.056722 -223.893888)
		(end 341.067136 -223.899984)
		(width 0.0889)
		(layer "B.Cu")
		(net "JTAG_DBP_CPU0_GTL_R_TCK")
	)
	(segment
		(start 349.617284 -224.389442)
		(end 349.617284 -224.373948)
		(width 0.0889)
		(layer "B.Cu")
		(net "JTAG_DBP_CPU0_GTL_R_TCK")
	)
	(segment
		(start 354.976684 -230.076756)
		(end 354.976684 -230.095298)
		(width 0.0889)
		(layer "B.Cu")
		(net "JTAG_DBP_CPU0_GTL_R_TCK")
	)
	(segment
		(start 354.224082 -228.783388)
		(end 354.230178 -228.786944)
		(width 0.0889)
		(layer "B.Cu")
		(net "JTAG_DBP_CPU0_GTL_R_TCK")
	)
	(segment
		(start 343.229184 -224.379536)
		(end 343.229184 -224.389442)
		(width 0.0889)
		(layer "B.Cu")
		(net "JTAG_DBP_CPU0_GTL_R_TCK")
	)
	(segment
		(start 332.337156 -223.460056)
		(end 332.337156 -223.663256)
		(width 0.0889)
		(layer "B.Cu")
		(net "JTAG_DBP_CPU0_GTL_R_TCK")
	)
	(segment
		(start 357.034592 -232.033826)
		(end 357.049578 -232.042462)
		(width 0.0889)
		(layer "B.Cu")
		(net "JTAG_DBP_CPU0_GTL_R_TCK")
	)
	(segment
		(start 358.639618 -232.52938)
		(end 358.640634 -232.528364)
		(width 0.0889)
		(layer "B.Cu")
		(net "JTAG_DBP_CPU0_GTL_R_TCK")
	)
	(segment
		(start 325.759318 -217.061288)
		(end 327.991724 -219.293694)
		(width 0.12954)
		(layer "B.Cu")
		(net "JTAG_DBP_CPU0_GTL_R_TCK")
	)
	(segment
		(start 345.108784 -224.379536)
		(end 345.108784 -224.389442)
		(width 0.0889)
		(layer "B.Cu")
		(net "JTAG_DBP_CPU0_GTL_R_TCK")
	)
	(segment
		(start 327.991724 -219.293694)
		(end 331.319886 -222.621856)
		(width 0.12954)
		(layer "B.Cu")
		(net "JTAG_DBP_CPU0_GTL_R_TCK")
	)
	(segment
		(start 346.988384 -224.379536)
		(end 346.988384 -224.389442)
		(width 0.0889)
		(layer "B.Cu")
		(net "JTAG_DBP_CPU0_GTL_R_TCK")
	)
	(segment
		(start 343.791032 -224.7138)
		(end 343.799922 -224.70872)
		(width 0.0889)
		(layer "B.Cu")
		(net "JTAG_DBP_CPU0_GTL_R_TCK")
	)
	(segment
		(start 358.306116 -233.691176)
		(end 358.512618 -233.61015)
		(width 0.0889)
		(layer "B.Cu")
		(net "JTAG_DBP_CPU0_GTL_R_TCK")
	)
	(segment
		(start 347.166946 -224.70872)
		(end 347.175836 -224.7138)
		(width 0.0889)
		(layer "B.Cu")
		(net "JTAG_DBP_CPU0_GTL_R_TCK")
	)
	(segment
		(start 332.337156 -223.663256)
		(end 332.62443 -223.95053)
		(width 0.0889)
		(layer "B.Cu")
		(net "JTAG_DBP_CPU0_GTL_R_TCK")
	)
	(segment
		(start 343.407746 -224.70872)
		(end 343.416636 -224.7138)
		(width 0.0889)
		(layer "B.Cu")
		(net "JTAG_DBP_CPU0_GTL_R_TCK")
	)
	(segment
		(start 332.983332 -223.899984)
		(end 332.998064 -223.891348)
		(width 0.0889)
		(layer "B.Cu")
		(net "JTAG_DBP_CPU0_GTL_R_TCK")
	)
	(segment
		(start 345.670632 -224.7138)
		(end 345.679522 -224.70872)
		(width 0.0889)
		(layer "B.Cu")
		(net "JTAG_DBP_CPU0_GTL_R_TCK")
	)
	(segment
		(start 351.687384 -226.003104)
		(end 351.687384 -226.017328)
		(width 0.0889)
		(layer "B.Cu")
		(net "JTAG_DBP_CPU0_GTL_R_TCK")
	)
	(segment
		(start 358.639618 -233.48315)
		(end 358.639618 -232.52938)
		(width 0.0889)
		(layer "B.Cu")
		(net "JTAG_DBP_CPU0_GTL_R_TCK")
	)
	(segment
		(start 331.319886 -222.621856)
		(end 331.498956 -222.621856)
		(width 0.12954)
		(layer "B.Cu")
		(net "JTAG_DBP_CPU0_GTL_R_TCK")
	)
	(segment
		(start 325.322438 -188.85916)
		(end 325.759318 -189.29604)
		(width 0.12954)
		(layer "B.Cu")
		(net "JTAG_DBP_CPU0_GTL_R_TCK")
	)
	(segment
		(start 339.648546 -224.70872)
		(end 339.657436 -224.7138)
		(width 0.0889)
		(layer "B.Cu")
		(net "JTAG_DBP_CPU0_GTL_R_TCK")
	)
	(segment
		(start 340.031832 -224.7138)
		(end 340.040722 -224.70872)
		(width 0.0889)
		(layer "B.Cu")
		(net "JTAG_DBP_CPU0_GTL_R_TCK")
	)
	(segment
		(start 347.550232 -224.7138)
		(end 347.559122 -224.70872)
		(width 0.0889)
		(layer "B.Cu")
		(net "JTAG_DBP_CPU0_GTL_R_TCK")
	)
	(segment
		(start 346.695522 -223.893888)
		(end 346.705936 -223.899984)
		(width 0.0889)
		(layer "B.Cu")
		(net "JTAG_DBP_CPU0_GTL_R_TCK")
	)
	(segment
		(start 341.528146 -224.70872)
		(end 341.537036 -224.7138)
		(width 0.0889)
		(layer "B.Cu")
		(net "JTAG_DBP_CPU0_GTL_R_TCK")
	)
	(segment
		(start 350.926146 -224.70872)
		(end 350.935036 -224.7138)
		(width 0.0889)
		(layer "B.Cu")
		(net "JTAG_DBP_CPU0_GTL_R_TCK")
	)
	(segment
		(start 337.590384 -224.373948)
		(end 337.590384 -224.389442)
		(width 0.0889)
		(layer "B.Cu")
		(net "JTAG_DBP_CPU0_GTL_R_TCK")
	)
	(segment
		(start 337.768946 -224.70872)
		(end 337.777836 -224.7138)
		(width 0.0889)
		(layer "B.Cu")
		(net "JTAG_DBP_CPU0_GTL_R_TCK")
	)
	(segment
		(start 345.287346 -224.70872)
		(end 345.296236 -224.7138)
		(width 0.0889)
		(layer "B.Cu")
		(net "JTAG_DBP_CPU0_GTL_R_TCK")
	)
	(segment
		(start 341.349584 -224.379536)
		(end 341.349584 -224.389442)
		(width 0.0889)
		(layer "B.Cu")
		(net "JTAG_DBP_CPU0_GTL_R_TCK")
	)
	(segment
		(start 338.152232 -224.7138)
		(end 338.161122 -224.70872)
		(width 0.0889)
		(layer "B.Cu")
		(net "JTAG_DBP_CPU0_GTL_R_TCK")
	)
	(segment
		(start 352.627184 -227.635054)
		(end 352.627184 -227.64496)
		(width 0.0889)
		(layer "B.Cu")
		(net "JTAG_DBP_CPU0_GTL_R_TCK")
	)
	(segment
		(start 343.978484 -224.389442)
		(end 343.978484 -224.373948)
		(width 0.0889)
		(layer "B.Cu")
		(net "JTAG_DBP_CPU0_GTL_R_TCK")
	)
	(segment
		(start 349.046546 -224.70872)
		(end 349.055436 -224.7138)
		(width 0.0889)
		(layer "B.Cu")
		(net "JTAG_DBP_CPU0_GTL_R_TCK")
	)
	(segment
		(start 351.395792 -225.522536)
		(end 351.404682 -225.527616)
		(width 0.0889)
		(layer "B.Cu")
		(net "JTAG_DBP_CPU0_GTL_R_TCK")
	)
	(segment
		(start 352.157284 -226.821238)
		(end 352.157284 -226.831144)
		(width 0.0889)
		(layer "B.Cu")
		(net "JTAG_DBP_CPU0_GTL_R_TCK")
	)
	(segment
		(start 353.189032 -227.969318)
		(end 353.203764 -227.960682)
		(width 0.0889)
		(layer "B.Cu")
		(net "JTAG_DBP_CPU0_GTL_R_TCK")
	)
	(segment
		(start 350.454722 -223.893888)
		(end 350.465136 -223.899984)
		(width 0.0889)
		(layer "B.Cu")
		(net "JTAG_DBP_CPU0_GTL_R_TCK")
	)
	(segment
		(start 338.339684 -224.389442)
		(end 338.339684 -224.373948)
		(width 0.0889)
		(layer "B.Cu")
		(net "JTAG_DBP_CPU0_GTL_R_TCK")
	)
	(segment
		(start 336.357468 -223.893888)
		(end 336.367882 -223.899984)
		(width 0.0889)
		(layer "B.Cu")
		(net "JTAG_DBP_CPU0_GTL_R_TCK")
	)
	(segment
		(start 342.936322 -223.893888)
		(end 342.946736 -223.899984)
		(width 0.0889)
		(layer "B.Cu")
		(net "JTAG_DBP_CPU0_GTL_R_TCK")
	)
	(segment
		(start 356.85603 -231.69245)
		(end 356.85603 -231.714548)
		(width 0.0889)
		(layer "B.Cu")
		(net "JTAG_DBP_CPU0_GTL_R_TCK")
	)
	(segment
		(start 348.867984 -224.379536)
		(end 348.867984 -224.389442)
		(width 0.0889)
		(layer "B.Cu")
		(net "JTAG_DBP_CPU0_GTL_R_TCK")
	)
	(segment
		(start 339.469984 -224.379536)
		(end 339.469984 -224.389442)
		(width 0.0889)
		(layer "B.Cu")
		(net "JTAG_DBP_CPU0_GTL_R_TCK")
	)
	(segment
		(start 355.44633 -230.884984)
		(end 355.44633 -230.909114)
		(width 0.0889)
		(layer "B.Cu")
		(net "JTAG_DBP_CPU0_GTL_R_TCK")
	)
	(segment
		(start 350.747584 -224.379536)
		(end 350.747584 -224.389442)
		(width 0.0889)
		(layer "B.Cu")
		(net "JTAG_DBP_CPU0_GTL_R_TCK")
	)
	(segment
		(start 351.865946 -226.336606)
		(end 351.874836 -226.341686)
		(width 0.0889)
		(layer "B.Cu")
		(net "JTAG_DBP_CPU0_GTL_R_TCK")
	)
	(segment
		(start 348.575122 -223.893888)
		(end 348.585536 -223.899984)
		(width 0.0889)
		(layer "B.Cu")
		(net "JTAG_DBP_CPU0_GTL_R_TCK")
	)
	(segment
		(start 341.911432 -224.7138)
		(end 341.920322 -224.70872)
		(width 0.0889)
		(layer "B.Cu")
		(net "JTAG_DBP_CPU0_GTL_R_TCK")
	)
	(segment
		(start 325.759318 -189.29604)
		(end 325.759318 -217.061288)
		(width 0.12954)
		(layer "B.Cu")
		(net "JTAG_DBP_CPU0_GTL_R_TCK")
	)
	(segment
		(start 352.805746 -227.964238)
		(end 352.814636 -227.969318)
		(width 0.0889)
		(layer "B.Cu")
		(net "JTAG_DBP_CPU0_GTL_R_TCK")
	)
	(segment
		(start 354.215192 -228.778308)
		(end 354.224082 -228.783388)
		(width 0.0889)
		(layer "B.Cu")
		(net "JTAG_DBP_CPU0_GTL_R_TCK")
	)
	(segment
		(start 347.737684 -224.389442)
		(end 347.737684 -224.373948)
		(width 0.0889)
		(layer "B.Cu")
		(net "JTAG_DBP_CPU0_GTL_R_TCK")
	)
	(segment
		(start 354.685346 -229.592124)
		(end 354.694236 -229.597204)
		(width 0.0889)
		(layer "B.Cu")
		(net "JTAG_DBP_CPU0_GTL_R_TCK")
	)
	(segment
		(start 349.429832 -224.7138)
		(end 349.438722 -224.70872)
		(width 0.0889)
		(layer "B.Cu")
		(net "JTAG_DBP_CPU0_GTL_R_TCK")
	)
	(segment
		(start 340.219284 -224.389442)
		(end 340.219284 -224.373948)
		(width 0.0889)
		(layer "B.Cu")
		(net "JTAG_DBP_CPU0_GTL_R_TCK")
	)
	(segment
		(start 332.62443 -223.95053)
		(end 332.796134 -223.95053)
		(width 0.0889)
		(layer "B.Cu")
		(net "JTAG_DBP_CPU0_GTL_R_TCK")
	)
	(segment
		(start 351.21723 -225.187764)
		(end 351.21723 -225.203258)
		(width 0.0889)
		(layer "B.Cu")
		(net "JTAG_DBP_CPU0_GTL_R_TCK")
	)
	(segment
		(start 344.815922 -223.893888)
		(end 344.826336 -223.899984)
		(width 0.0889)
		(layer "B.Cu")
		(net "JTAG_DBP_CPU0_GTL_R_TCK")
	)
	(segment
		(start 331.498956 -222.621856)
		(end 332.337156 -223.460056)
		(width 0.12954)
		(layer "B.Cu")
		(net "JTAG_DBP_CPU0_GTL_R_TCK")
	)
	(arc
		(start 354.506784 -229.272846)
		(mid 354.554463 -229.455746)
		(end 354.685346 -229.592124)
		(width 0.0889)
		(layer "B.Cu")
		(net "JTAG_DBP_CPU0_GTL_R_TCK")
	)
	(arc
		(start 337.590384 -224.389442)
		(mid 337.638063 -224.572342)
		(end 337.768946 -224.70872)
		(width 0.0889)
		(layer "B.Cu")
		(net "JTAG_DBP_CPU0_GTL_R_TCK")
	)
	(arc
		(start 348.585536 -223.899984)
		(mid 348.789871 -224.102589)
		(end 348.867984 -224.379536)
		(width 0.0889)
		(layer "B.Cu")
		(net "JTAG_DBP_CPU0_GTL_R_TCK")
	)
	(arc
		(start 345.296236 -224.7138)
		(mid 345.483434 -224.763943)
		(end 345.670632 -224.7138)
		(width 0.0889)
		(layer "B.Cu")
		(net "JTAG_DBP_CPU0_GTL_R_TCK")
	)
	(arc
		(start 354.976684 -230.095298)
		(mid 355.028954 -230.277663)
		(end 355.163882 -230.41102)
		(width 0.0889)
		(layer "B.Cu")
		(net "JTAG_DBP_CPU0_GTL_R_TCK")
	)
	(arc
		(start 357.796084 -233.34218)
		(mid 357.959062 -233.65117)
		(end 358.306116 -233.691176)
		(width 0.0889)
		(layer "B.Cu")
		(net "JTAG_DBP_CPU0_GTL_R_TCK")
	)
	(arc
		(start 338.339684 -224.373948)
		(mid 338.419054 -224.100214)
		(end 338.621878 -223.899984)
		(width 0.0889)
		(layer "B.Cu")
		(net "JTAG_DBP_CPU0_GTL_R_TCK")
	)
	(arc
		(start 341.349584 -224.389442)
		(mid 341.397263 -224.572342)
		(end 341.528146 -224.70872)
		(width 0.0889)
		(layer "B.Cu")
		(net "JTAG_DBP_CPU0_GTL_R_TCK")
	)
	(arc
		(start 342.946736 -223.899984)
		(mid 343.151071 -224.102589)
		(end 343.229184 -224.379536)
		(width 0.0889)
		(layer "B.Cu")
		(net "JTAG_DBP_CPU0_GTL_R_TCK")
	)
	(arc
		(start 354.03663 -228.45903)
		(mid 354.084309 -228.64193)
		(end 354.215192 -228.778308)
		(width 0.0889)
		(layer "B.Cu")
		(net "JTAG_DBP_CPU0_GTL_R_TCK")
	)
	(arc
		(start 347.175836 -224.7138)
		(mid 347.363034 -224.763943)
		(end 347.550232 -224.7138)
		(width 0.0889)
		(layer "B.Cu")
		(net "JTAG_DBP_CPU0_GTL_R_TCK")
	)
	(arc
		(start 340.040722 -224.70872)
		(mid 340.171636 -224.57236)
		(end 340.219284 -224.389442)
		(width 0.0889)
		(layer "B.Cu")
		(net "JTAG_DBP_CPU0_GTL_R_TCK")
	)
	(arc
		(start 352.627184 -227.64496)
		(mid 352.674863 -227.82786)
		(end 352.805746 -227.964238)
		(width 0.0889)
		(layer "B.Cu")
		(net "JTAG_DBP_CPU0_GTL_R_TCK")
	)
	(arc
		(start 340.501478 -223.899984)
		(mid 340.778291 -223.824114)
		(end 341.056722 -223.893888)
		(width 0.0889)
		(layer "B.Cu")
		(net "JTAG_DBP_CPU0_GTL_R_TCK")
	)
	(arc
		(start 339.469984 -224.389442)
		(mid 339.517663 -224.572342)
		(end 339.648546 -224.70872)
		(width 0.0889)
		(layer "B.Cu")
		(net "JTAG_DBP_CPU0_GTL_R_TCK")
	)
	(arc
		(start 354.694236 -229.597204)
		(mid 354.898571 -229.799809)
		(end 354.976684 -230.076756)
		(width 0.0889)
		(layer "B.Cu")
		(net "JTAG_DBP_CPU0_GTL_R_TCK")
	)
	(arc
		(start 350.465136 -223.899984)
		(mid 350.669471 -224.102589)
		(end 350.747584 -224.379536)
		(width 0.0889)
		(layer "B.Cu")
		(net "JTAG_DBP_CPU0_GTL_R_TCK")
	)
	(arc
		(start 347.559122 -224.70872)
		(mid 347.690036 -224.57236)
		(end 347.737684 -224.389442)
		(width 0.0889)
		(layer "B.Cu")
		(net "JTAG_DBP_CPU0_GTL_R_TCK")
	)
	(arc
		(start 332.998064 -223.891348)
		(mid 333.274539 -223.824028)
		(end 333.548736 -223.899984)
		(width 0.0889)
		(layer "B.Cu")
		(net "JTAG_DBP_CPU0_GTL_R_TCK")
	)
	(arc
		(start 357.049578 -232.042462)
		(mid 357.252165 -232.248813)
		(end 357.326184 -232.528364)
		(width 0.0889)
		(layer "B.Cu")
		(net "JTAG_DBP_CPU0_GTL_R_TCK")
	)
	(arc
		(start 357.326184 -232.528364)
		(mid 357.373863 -232.711264)
		(end 357.504746 -232.847642)
		(width 0.0889)
		(layer "B.Cu")
		(net "JTAG_DBP_CPU0_GTL_R_TCK")
	)
	(arc
		(start 352.344736 -227.155502)
		(mid 352.549071 -227.358107)
		(end 352.627184 -227.635054)
		(width 0.0889)
		(layer "B.Cu")
		(net "JTAG_DBP_CPU0_GTL_R_TCK")
	)
	(arc
		(start 355.44633 -230.909114)
		(mid 355.637204 -231.226923)
		(end 356.007924 -231.224836)
		(width 0.0889)
		(layer "B.Cu")
		(net "JTAG_DBP_CPU0_GTL_R_TCK")
	)
	(arc
		(start 339.187536 -223.899984)
		(mid 339.391871 -224.102589)
		(end 339.469984 -224.379536)
		(width 0.0889)
		(layer "B.Cu")
		(net "JTAG_DBP_CPU0_GTL_R_TCK")
	)
	(arc
		(start 333.923132 -223.899984)
		(mid 334.205834 -223.824208)
		(end 334.488536 -223.899984)
		(width 0.0889)
		(layer "B.Cu")
		(net "JTAG_DBP_CPU0_GTL_R_TCK")
	)
	(arc
		(start 347.737684 -224.373948)
		(mid 347.817054 -224.100214)
		(end 348.019878 -223.899984)
		(width 0.0889)
		(layer "B.Cu")
		(net "JTAG_DBP_CPU0_GTL_R_TCK")
	)
	(arc
		(start 355.163882 -230.41102)
		(mid 355.36688 -230.611189)
		(end 355.44633 -230.884984)
		(width 0.0889)
		(layer "B.Cu")
		(net "JTAG_DBP_CPU0_GTL_R_TCK")
	)
	(arc
		(start 349.438722 -224.70872)
		(mid 349.569636 -224.57236)
		(end 349.617284 -224.389442)
		(width 0.0889)
		(layer "B.Cu")
		(net "JTAG_DBP_CPU0_GTL_R_TCK")
	)
	(arc
		(start 343.799922 -224.70872)
		(mid 343.930836 -224.57236)
		(end 343.978484 -224.389442)
		(width 0.0889)
		(layer "B.Cu")
		(net "JTAG_DBP_CPU0_GTL_R_TCK")
	)
	(arc
		(start 333.548736 -223.899984)
		(mid 333.735934 -223.950127)
		(end 333.923132 -223.899984)
		(width 0.0889)
		(layer "B.Cu")
		(net "JTAG_DBP_CPU0_GTL_R_TCK")
	)
	(arc
		(start 340.219284 -224.373948)
		(mid 340.298654 -224.100214)
		(end 340.501478 -223.899984)
		(width 0.0889)
		(layer "B.Cu")
		(net "JTAG_DBP_CPU0_GTL_R_TCK")
	)
	(arc
		(start 332.796134 -223.95053)
		(mid 332.893057 -223.937572)
		(end 332.983332 -223.899984)
		(width 0.0889)
		(layer "B.Cu")
		(net "JTAG_DBP_CPU0_GTL_R_TCK")
	)
	(arc
		(start 344.826336 -223.899984)
		(mid 345.030671 -224.102589)
		(end 345.108784 -224.379536)
		(width 0.0889)
		(layer "B.Cu")
		(net "JTAG_DBP_CPU0_GTL_R_TCK")
	)
	(arc
		(start 348.867984 -224.389442)
		(mid 348.915663 -224.572342)
		(end 349.046546 -224.70872)
		(width 0.0889)
		(layer "B.Cu")
		(net "JTAG_DBP_CPU0_GTL_R_TCK")
	)
	(arc
		(start 341.067136 -223.899984)
		(mid 341.271471 -224.102589)
		(end 341.349584 -224.379536)
		(width 0.0889)
		(layer "B.Cu")
		(net "JTAG_DBP_CPU0_GTL_R_TCK")
	)
	(arc
		(start 338.161122 -224.70872)
		(mid 338.292036 -224.57236)
		(end 338.339684 -224.389442)
		(width 0.0889)
		(layer "B.Cu")
		(net "JTAG_DBP_CPU0_GTL_R_TCK")
	)
	(arc
		(start 334.488536 -223.899984)
		(mid 334.675734 -223.950127)
		(end 334.862932 -223.899984)
		(width 0.0889)
		(layer "B.Cu")
		(net "JTAG_DBP_CPU0_GTL_R_TCK")
	)
	(arc
		(start 352.814636 -227.969318)
		(mid 353.001834 -228.019461)
		(end 353.189032 -227.969318)
		(width 0.0889)
		(layer "B.Cu")
		(net "JTAG_DBP_CPU0_GTL_R_TCK")
	)
	(arc
		(start 345.858084 -224.373948)
		(mid 345.937454 -224.100214)
		(end 346.140278 -223.899984)
		(width 0.0889)
		(layer "B.Cu")
		(net "JTAG_DBP_CPU0_GTL_R_TCK")
	)
	(arc
		(start 357.519732 -232.856278)
		(mid 357.722145 -233.062691)
		(end 357.796084 -233.34218)
		(width 0.0889)
		(layer "B.Cu")
		(net "JTAG_DBP_CPU0_GTL_R_TCK")
	)
	(arc
		(start 335.802732 -223.899984)
		(mid 336.079291 -223.824241)
		(end 336.357468 -223.893888)
		(width 0.0889)
		(layer "B.Cu")
		(net "JTAG_DBP_CPU0_GTL_R_TCK")
	)
	(arc
		(start 344.260678 -223.899984)
		(mid 344.537491 -223.824114)
		(end 344.815922 -223.893888)
		(width 0.0889)
		(layer "B.Cu")
		(net "JTAG_DBP_CPU0_GTL_R_TCK")
	)
	(arc
		(start 350.747584 -224.389442)
		(mid 350.795263 -224.572342)
		(end 350.926146 -224.70872)
		(width 0.0889)
		(layer "B.Cu")
		(net "JTAG_DBP_CPU0_GTL_R_TCK")
	)
	(arc
		(start 356.007924 -231.224836)
		(mid 356.563962 -231.219262)
		(end 356.85603 -231.69245)
		(width 0.0889)
		(layer "B.Cu")
		(net "JTAG_DBP_CPU0_GTL_R_TCK")
	)
	(arc
		(start 339.657436 -224.7138)
		(mid 339.844634 -224.763943)
		(end 340.031832 -224.7138)
		(width 0.0889)
		(layer "B.Cu")
		(net "JTAG_DBP_CPU0_GTL_R_TCK")
	)
	(arc
		(start 351.874836 -226.341686)
		(mid 352.079171 -226.544291)
		(end 352.157284 -226.821238)
		(width 0.0889)
		(layer "B.Cu")
		(net "JTAG_DBP_CPU0_GTL_R_TCK")
	)
	(arc
		(start 352.157284 -226.831144)
		(mid 352.204963 -227.014044)
		(end 352.335846 -227.150422)
		(width 0.0889)
		(layer "B.Cu")
		(net "JTAG_DBP_CPU0_GTL_R_TCK")
	)
	(arc
		(start 336.367882 -223.899984)
		(mid 336.55508 -223.950127)
		(end 336.742278 -223.899984)
		(width 0.0889)
		(layer "B.Cu")
		(net "JTAG_DBP_CPU0_GTL_R_TCK")
	)
	(arc
		(start 353.754436 -227.969318)
		(mid 353.955718 -228.166805)
		(end 354.03663 -228.436932)
		(width 0.0889)
		(layer "B.Cu")
		(net "JTAG_DBP_CPU0_GTL_R_TCK")
	)
	(arc
		(start 350.935036 -224.7138)
		(mid 351.137859 -224.914031)
		(end 351.21723 -225.187764)
		(width 0.0889)
		(layer "B.Cu")
		(net "JTAG_DBP_CPU0_GTL_R_TCK")
	)
	(arc
		(start 334.862932 -223.899984)
		(mid 335.145634 -223.824208)
		(end 335.428336 -223.899984)
		(width 0.0889)
		(layer "B.Cu")
		(net "JTAG_DBP_CPU0_GTL_R_TCK")
	)
	(arc
		(start 356.85603 -231.714548)
		(mid 356.903709 -231.897448)
		(end 357.034592 -232.033826)
		(width 0.0889)
		(layer "B.Cu")
		(net "JTAG_DBP_CPU0_GTL_R_TCK")
	)
	(arc
		(start 342.381078 -223.899984)
		(mid 342.657891 -223.824114)
		(end 342.936322 -223.893888)
		(width 0.0889)
		(layer "B.Cu")
		(net "JTAG_DBP_CPU0_GTL_R_TCK")
	)
	(arc
		(start 341.537036 -224.7138)
		(mid 341.724234 -224.763943)
		(end 341.911432 -224.7138)
		(width 0.0889)
		(layer "B.Cu")
		(net "JTAG_DBP_CPU0_GTL_R_TCK")
	)
	(arc
		(start 349.617284 -224.373948)
		(mid 349.696654 -224.100214)
		(end 349.899478 -223.899984)
		(width 0.0889)
		(layer "B.Cu")
		(net "JTAG_DBP_CPU0_GTL_R_TCK")
	)
	(arc
		(start 349.899478 -223.899984)
		(mid 350.176291 -223.824114)
		(end 350.454722 -223.893888)
		(width 0.0889)
		(layer "B.Cu")
		(net "JTAG_DBP_CPU0_GTL_R_TCK")
	)
	(arc
		(start 346.140278 -223.899984)
		(mid 346.417091 -223.824114)
		(end 346.695522 -223.893888)
		(width 0.0889)
		(layer "B.Cu")
		(net "JTAG_DBP_CPU0_GTL_R_TCK")
	)
	(arc
		(start 337.777836 -224.7138)
		(mid 337.965034 -224.763943)
		(end 338.152232 -224.7138)
		(width 0.0889)
		(layer "B.Cu")
		(net "JTAG_DBP_CPU0_GTL_R_TCK")
	)
	(arc
		(start 341.920322 -224.70872)
		(mid 342.051236 -224.57236)
		(end 342.098884 -224.389442)
		(width 0.0889)
		(layer "B.Cu")
		(net "JTAG_DBP_CPU0_GTL_R_TCK")
	)
	(arc
		(start 345.679522 -224.70872)
		(mid 345.810436 -224.57236)
		(end 345.858084 -224.389442)
		(width 0.0889)
		(layer "B.Cu")
		(net "JTAG_DBP_CPU0_GTL_R_TCK")
	)
	(arc
		(start 351.21723 -225.203258)
		(mid 351.264909 -225.386158)
		(end 351.395792 -225.522536)
		(width 0.0889)
		(layer "B.Cu")
		(net "JTAG_DBP_CPU0_GTL_R_TCK")
	)
	(arc
		(start 349.055436 -224.7138)
		(mid 349.242634 -224.763943)
		(end 349.429832 -224.7138)
		(width 0.0889)
		(layer "B.Cu")
		(net "JTAG_DBP_CPU0_GTL_R_TCK")
	)
	(arc
		(start 343.229184 -224.389442)
		(mid 343.276863 -224.572342)
		(end 343.407746 -224.70872)
		(width 0.0889)
		(layer "B.Cu")
		(net "JTAG_DBP_CPU0_GTL_R_TCK")
	)
	(arc
		(start 354.230178 -228.786944)
		(mid 354.432765 -228.993295)
		(end 354.506784 -229.272846)
		(width 0.0889)
		(layer "B.Cu")
		(net "JTAG_DBP_CPU0_GTL_R_TCK")
	)
	(arc
		(start 337.30819 -223.899984)
		(mid 337.511013 -224.100215)
		(end 337.590384 -224.373948)
		(width 0.0889)
		(layer "B.Cu")
		(net "JTAG_DBP_CPU0_GTL_R_TCK")
	)
	(arc
		(start 351.687384 -226.017328)
		(mid 351.735063 -226.200228)
		(end 351.865946 -226.336606)
		(width 0.0889)
		(layer "B.Cu")
		(net "JTAG_DBP_CPU0_GTL_R_TCK")
	)
	(arc
		(start 348.019878 -223.899984)
		(mid 348.296691 -223.824114)
		(end 348.575122 -223.893888)
		(width 0.0889)
		(layer "B.Cu")
		(net "JTAG_DBP_CPU0_GTL_R_TCK")
	)
	(arc
		(start 343.416636 -224.7138)
		(mid 343.603834 -224.763943)
		(end 343.791032 -224.7138)
		(width 0.0889)
		(layer "B.Cu")
		(net "JTAG_DBP_CPU0_GTL_R_TCK")
	)
	(arc
		(start 338.621878 -223.899984)
		(mid 338.898691 -223.824114)
		(end 339.177122 -223.893888)
		(width 0.0889)
		(layer "B.Cu")
		(net "JTAG_DBP_CPU0_GTL_R_TCK")
	)
	(arc
		(start 353.203764 -227.960682)
		(mid 353.480205 -227.893516)
		(end 353.754436 -227.969318)
		(width 0.0889)
		(layer "B.Cu")
		(net "JTAG_DBP_CPU0_GTL_R_TCK")
	)
	(arc
		(start 335.428336 -223.899984)
		(mid 335.615534 -223.950127)
		(end 335.802732 -223.899984)
		(width 0.0889)
		(layer "B.Cu")
		(net "JTAG_DBP_CPU0_GTL_R_TCK")
	)
	(arc
		(start 346.705936 -223.899984)
		(mid 346.910271 -224.102589)
		(end 346.988384 -224.379536)
		(width 0.0889)
		(layer "B.Cu")
		(net "JTAG_DBP_CPU0_GTL_R_TCK")
	)
	(arc
		(start 343.978484 -224.373948)
		(mid 344.057854 -224.100214)
		(end 344.260678 -223.899984)
		(width 0.0889)
		(layer "B.Cu")
		(net "JTAG_DBP_CPU0_GTL_R_TCK")
	)
	(arc
		(start 336.742278 -223.899984)
		(mid 337.025234 -223.824081)
		(end 337.30819 -223.899984)
		(width 0.0889)
		(layer "B.Cu")
		(net "JTAG_DBP_CPU0_GTL_R_TCK")
	)
	(arc
		(start 342.098884 -224.373948)
		(mid 342.178254 -224.100214)
		(end 342.381078 -223.899984)
		(width 0.0889)
		(layer "B.Cu")
		(net "JTAG_DBP_CPU0_GTL_R_TCK")
	)
	(arc
		(start 345.108784 -224.389442)
		(mid 345.156463 -224.572342)
		(end 345.287346 -224.70872)
		(width 0.0889)
		(layer "B.Cu")
		(net "JTAG_DBP_CPU0_GTL_R_TCK")
	)
	(arc
		(start 351.404682 -225.527616)
		(mid 351.608163 -225.72842)
		(end 351.687384 -226.003104)
		(width 0.0889)
		(layer "B.Cu")
		(net "JTAG_DBP_CPU0_GTL_R_TCK")
	)
	(arc
		(start 346.988384 -224.389442)
		(mid 347.036063 -224.572342)
		(end 347.166946 -224.70872)
		(width 0.0889)
		(layer "B.Cu")
		(net "JTAG_DBP_CPU0_GTL_R_TCK")
	)
	(segment
		(start 396.0876 -58.377328)
		(end 396.0876 -56.373268)
		(width 0.12954)
		(layer "F.Cu")
		(net "JTAG_DBP_BOOT_HALT_N")
	)
	(segment
		(start 396.0876 -56.373268)
		(end 396.710916 -55.749952)
		(width 0.12954)
		(layer "F.Cu")
		(net "JTAG_DBP_BOOT_HALT_N")
	)
	(segment
		(start 396.710916 -55.749952)
		(end 397.765016 -55.749952)
		(width 0.12954)
		(layer "F.Cu")
		(net "JTAG_DBP_BOOT_HALT_N")
	)
	(via
		(at 396.0876 -58.377328)
		(size 0.508)
		(drill 0.254)
		(layers "F.Cu" "B.Cu")
		(net "JTAG_DBP_BOOT_HALT_N")
	)
	(segment
		(start 403.602698 -59.939428)
		(end 403.602698 -58.79846)
		(width 0.12954)
		(layer "B.Cu")
		(net "JTAG_DBP_BOOT_HALT_N")
	)
	(segment
		(start 396.0876 -58.377328)
		(end 403.181566 -58.377328)
		(width 0.12954)
		(layer "B.Cu")
		(net "JTAG_DBP_BOOT_HALT_N")
	)
	(segment
		(start 403.181566 -58.377328)
		(end 403.602698 -58.79846)
		(width 0.12954)
		(layer "B.Cu")
		(net "JTAG_DBP_BOOT_HALT_N")
	)
	(segment
		(start 302.25619 -115.021614)
		(end 326.213724 -111.4679)
		(width 0.12954)
		(layer "F.Cu")
		(net "JTAG_DBP_BMC_PREQ_R_N")
	)
	(segment
		(start 226.3775 -114.605308)
		(end 293.421562 -114.605308)
		(width 0.12954)
		(layer "F.Cu")
		(net "JTAG_DBP_BMC_PREQ_R_N")
	)
	(segment
		(start 192.146428 -123.414028)
		(end 194.60972 -123.414028)
		(width 0.12954)
		(layer "F.Cu")
		(net "JTAG_DBP_BMC_PREQ_R_N")
	)
	(segment
		(start 202.8952 -122.8598)
		(end 218.123008 -122.8598)
		(width 0.12954)
		(layer "F.Cu")
		(net "JTAG_DBP_BMC_PREQ_R_N")
	)
	(segment
		(start 357.943404 -108.342684)
		(end 370.021358 -108.342684)
		(width 0.12954)
		(layer "F.Cu")
		(net "JTAG_DBP_BMC_PREQ_R_N")
	)
	(segment
		(start 187.76188 -118.575328)
		(end 189.8015 -120.614948)
		(width 0.12954)
		(layer "F.Cu")
		(net "JTAG_DBP_BMC_PREQ_R_N")
	)
	(segment
		(start 191.7192 -121.498868)
		(end 191.7192 -122.9868)
		(width 0.12954)
		(layer "F.Cu")
		(net "JTAG_DBP_BMC_PREQ_R_N")
	)
	(segment
		(start 370.021358 -107.733084)
		(end 370.021358 -108.342684)
		(width 0.12954)
		(layer "F.Cu")
		(net "JTAG_DBP_BMC_PREQ_R_N")
	)
	(segment
		(start 191.7192 -122.9868)
		(end 192.146428 -123.414028)
		(width 0.12954)
		(layer "F.Cu")
		(net "JTAG_DBP_BMC_PREQ_R_N")
	)
	(segment
		(start 294.42664 -115.021614)
		(end 302.25619 -115.021614)
		(width 0.12954)
		(layer "F.Cu")
		(net "JTAG_DBP_BMC_PREQ_R_N")
	)
	(segment
		(start 326.213724 -111.4679)
		(end 357.943404 -108.342684)
		(width 0.12954)
		(layer "F.Cu")
		(net "JTAG_DBP_BMC_PREQ_R_N")
	)
	(segment
		(start 218.123008 -122.8598)
		(end 226.3775 -114.605308)
		(width 0.12954)
		(layer "F.Cu")
		(net "JTAG_DBP_BMC_PREQ_R_N")
	)
	(segment
		(start 194.60972 -123.414028)
		(end 196.1642 -121.859548)
		(width 0.12954)
		(layer "F.Cu")
		(net "JTAG_DBP_BMC_PREQ_R_N")
	)
	(segment
		(start 186.955684 -118.575328)
		(end 187.76188 -118.575328)
		(width 0.12954)
		(layer "F.Cu")
		(net "JTAG_DBP_BMC_PREQ_R_N")
	)
	(segment
		(start 196.1642 -121.859548)
		(end 201.894948 -121.859548)
		(width 0.12954)
		(layer "F.Cu")
		(net "JTAG_DBP_BMC_PREQ_R_N")
	)
	(segment
		(start 189.8015 -120.614948)
		(end 190.83528 -120.614948)
		(width 0.12954)
		(layer "F.Cu")
		(net "JTAG_DBP_BMC_PREQ_R_N")
	)
	(segment
		(start 190.83528 -120.614948)
		(end 191.7192 -121.498868)
		(width 0.12954)
		(layer "F.Cu")
		(net "JTAG_DBP_BMC_PREQ_R_N")
	)
	(segment
		(start 293.421562 -114.605308)
		(end 294.42664 -115.021614)
		(width 0.12954)
		(layer "F.Cu")
		(net "JTAG_DBP_BMC_PREQ_R_N")
	)
	(segment
		(start 201.894948 -121.859548)
		(end 202.8952 -122.8598)
		(width 0.12954)
		(layer "F.Cu")
		(net "JTAG_DBP_BMC_PREQ_R_N")
	)
	(via
		(at 370.021358 -108.342684)
		(size 0.508)
		(drill 0.254)
		(layers "F.Cu" "B.Cu")
		(net "JTAG_DBP_BMC_PREQ_R_N")
	)
	(segment
		(start 370.372386 -103.410766)
		(end 370.372386 -102.106984)
		(width 0.12954)
		(layer "F.Cu")
		(net "JTAG_DBP_BMC_PREQ_R1_N")
	)
	(segment
		(start 369.733068 -104.050084)
		(end 370.372386 -103.410766)
		(width 0.12954)
		(layer "F.Cu")
		(net "JTAG_DBP_BMC_PREQ_R1_N")
	)
	(via
		(at 145.415 -8.346948)
		(size 0.508)
		(drill 0.254)
		(layers "F.Cu" "B.Cu")
		(net "JTAG_DBP_BMC_PREQ_R1_N")
	)
	(via
		(at 369.733068 -104.050084)
		(size 0.508)
		(drill 0.254)
		(layers "F.Cu" "B.Cu")
		(net "JTAG_DBP_BMC_PREQ_R1_N")
	)
	(segment
		(start 145.415 -8.962898)
		(end 145.415 -8.346948)
		(width 0.12954)
		(layer "B.Cu")
		(net "JTAG_DBP_BMC_PREQ_R1_N")
	)
	(segment
		(start 311.02554 -14.150848)
		(end 310.00954 -15.166848)
		(width 0.127)
		(layer "In13.Cu")
		(net "JTAG_DBP_BMC_PREQ_R1_N")
	)
	(segment
		(start 370.1542 -93.030548)
		(end 372.0084 -93.030548)
		(width 0.127)
		(layer "In13.Cu")
		(net "JTAG_DBP_BMC_PREQ_R1_N")
	)
	(segment
		(start 272.777458 -30.44063)
		(end 257.510788 -36.764468)
		(width 0.127)
		(layer "In13.Cu")
		(net "JTAG_DBP_BMC_PREQ_R1_N")
	)
	(segment
		(start 397.7132 -64.760348)
		(end 397.7132 -49.748948)
		(width 0.127)
		(layer "In13.Cu")
		(net "JTAG_DBP_BMC_PREQ_R1_N")
	)
	(segment
		(start 166.5478 -7.381748)
		(end 146.3802 -7.381748)
		(width 0.127)
		(layer "In13.Cu")
		(net "JTAG_DBP_BMC_PREQ_R1_N")
	)
	(segment
		(start 369.31981 -93.864938)
		(end 370.1542 -93.030548)
		(width 0.127)
		(layer "In13.Cu")
		(net "JTAG_DBP_BMC_PREQ_R1_N")
	)
	(segment
		(start 186.0804 -13.249148)
		(end 182.8292 -9.997948)
		(width 0.127)
		(layer "In13.Cu")
		(net "JTAG_DBP_BMC_PREQ_R1_N")
	)
	(segment
		(start 223.721168 -36.764468)
		(end 221.610174 -34.653474)
		(width 0.127)
		(layer "In13.Cu")
		(net "JTAG_DBP_BMC_PREQ_R1_N")
	)
	(segment
		(start 310.00954 -15.166848)
		(end 307.315108 -15.166848)
		(width 0.127)
		(layer "In13.Cu")
		(net "JTAG_DBP_BMC_PREQ_R1_N")
	)
	(segment
		(start 182.8292 -9.997948)
		(end 180.721 -9.997948)
		(width 0.127)
		(layer "In13.Cu")
		(net "JTAG_DBP_BMC_PREQ_R1_N")
	)
	(segment
		(start 191.3382 -12.588748)
		(end 190.6778 -13.249148)
		(width 0.127)
		(layer "In13.Cu")
		(net "JTAG_DBP_BMC_PREQ_R1_N")
	)
	(segment
		(start 274.428966 -28.789122)
		(end 272.777458 -30.44063)
		(width 0.127)
		(layer "In13.Cu")
		(net "JTAG_DBP_BMC_PREQ_R1_N")
	)
	(segment
		(start 208.384648 -15.419832)
		(end 196.429884 -15.419832)
		(width 0.127)
		(layer "In13.Cu")
		(net "JTAG_DBP_BMC_PREQ_R1_N")
	)
	(segment
		(start 178.8414 -8.118348)
		(end 167.2844 -8.118348)
		(width 0.127)
		(layer "In13.Cu")
		(net "JTAG_DBP_BMC_PREQ_R1_N")
	)
	(segment
		(start 257.510788 -36.764468)
		(end 223.721168 -36.764468)
		(width 0.127)
		(layer "In13.Cu")
		(net "JTAG_DBP_BMC_PREQ_R1_N")
	)
	(segment
		(start 190.6778 -13.249148)
		(end 186.0804 -13.249148)
		(width 0.127)
		(layer "In13.Cu")
		(net "JTAG_DBP_BMC_PREQ_R1_N")
	)
	(segment
		(start 146.3802 -7.381748)
		(end 145.415 -8.346948)
		(width 0.127)
		(layer "In13.Cu")
		(net "JTAG_DBP_BMC_PREQ_R1_N")
	)
	(segment
		(start 215.876124 -19.070828)
		(end 212.035644 -19.070828)
		(width 0.127)
		(layer "In13.Cu")
		(net "JTAG_DBP_BMC_PREQ_R1_N")
	)
	(segment
		(start 167.2844 -8.118348)
		(end 166.5478 -7.381748)
		(width 0.127)
		(layer "In13.Cu")
		(net "JTAG_DBP_BMC_PREQ_R1_N")
	)
	(segment
		(start 221.610174 -34.653474)
		(end 221.610174 -24.804878)
		(width 0.127)
		(layer "In13.Cu")
		(net "JTAG_DBP_BMC_PREQ_R1_N")
	)
	(segment
		(start 307.315108 -15.166848)
		(end 274.428966 -28.789122)
		(width 0.127)
		(layer "In13.Cu")
		(net "JTAG_DBP_BMC_PREQ_R1_N")
	)
	(segment
		(start 212.035644 -19.070828)
		(end 208.384648 -15.419832)
		(width 0.127)
		(layer "In13.Cu")
		(net "JTAG_DBP_BMC_PREQ_R1_N")
	)
	(segment
		(start 221.610174 -24.804878)
		(end 215.876124 -19.070828)
		(width 0.127)
		(layer "In13.Cu")
		(net "JTAG_DBP_BMC_PREQ_R1_N")
	)
	(segment
		(start 395.4272 -79.898748)
		(end 395.4272 -67.046348)
		(width 0.127)
		(layer "In13.Cu")
		(net "JTAG_DBP_BMC_PREQ_R1_N")
	)
	(segment
		(start 372.4656 -92.573348)
		(end 382.7526 -92.573348)
		(width 0.127)
		(layer "In13.Cu")
		(net "JTAG_DBP_BMC_PREQ_R1_N")
	)
	(segment
		(start 340.056978 -14.150848)
		(end 311.02554 -14.150848)
		(width 0.127)
		(layer "In13.Cu")
		(net "JTAG_DBP_BMC_PREQ_R1_N")
	)
	(segment
		(start 193.5988 -12.588748)
		(end 191.3382 -12.588748)
		(width 0.127)
		(layer "In13.Cu")
		(net "JTAG_DBP_BMC_PREQ_R1_N")
	)
	(segment
		(start 372.0084 -93.030548)
		(end 372.4656 -92.573348)
		(width 0.127)
		(layer "In13.Cu")
		(net "JTAG_DBP_BMC_PREQ_R1_N")
	)
	(segment
		(start 369.31981 -103.636826)
		(end 369.31981 -93.864938)
		(width 0.127)
		(layer "In13.Cu")
		(net "JTAG_DBP_BMC_PREQ_R1_N")
	)
	(segment
		(start 180.721 -9.997948)
		(end 178.8414 -8.118348)
		(width 0.127)
		(layer "In13.Cu")
		(net "JTAG_DBP_BMC_PREQ_R1_N")
	)
	(segment
		(start 369.733068 -104.050084)
		(end 369.31981 -103.636826)
		(width 0.127)
		(layer "In13.Cu")
		(net "JTAG_DBP_BMC_PREQ_R1_N")
	)
	(segment
		(start 358.477058 -21.780754)
		(end 340.056978 -14.150848)
		(width 0.127)
		(layer "In13.Cu")
		(net "JTAG_DBP_BMC_PREQ_R1_N")
	)
	(segment
		(start 196.429884 -15.419832)
		(end 193.5988 -12.588748)
		(width 0.127)
		(layer "In13.Cu")
		(net "JTAG_DBP_BMC_PREQ_R1_N")
	)
	(segment
		(start 392.434064 -44.469812)
		(end 358.477058 -21.780754)
		(width 0.127)
		(layer "In13.Cu")
		(net "JTAG_DBP_BMC_PREQ_R1_N")
	)
	(segment
		(start 395.4272 -67.046348)
		(end 397.7132 -64.760348)
		(width 0.127)
		(layer "In13.Cu")
		(net "JTAG_DBP_BMC_PREQ_R1_N")
	)
	(segment
		(start 382.7526 -92.573348)
		(end 395.4272 -79.898748)
		(width 0.127)
		(layer "In13.Cu")
		(net "JTAG_DBP_BMC_PREQ_R1_N")
	)
	(segment
		(start 397.7132 -49.748948)
		(end 392.434064 -44.469812)
		(width 0.127)
		(layer "In13.Cu")
		(net "JTAG_DBP_BMC_PREQ_R1_N")
	)
	(segment
		(start 186.155584 -111.375444)
		(end 186.555634 -110.975394)
		(width 0.12954)
		(layer "F.Cu")
		(net "JTAG_DBP_BMC_PRDY_R_N")
	)
	(segment
		(start 380.538736 -93.287342)
		(end 380.538736 -93.928692)
		(width 0.12954)
		(layer "F.Cu")
		(net "JTAG_DBP_BMC_PRDY_R_N")
	)
	(via
		(at 380.538736 -93.928692)
		(size 0.508)
		(drill 0.254)
		(layers "F.Cu" "B.Cu")
		(net "JTAG_DBP_BMC_PRDY_R_N")
	)
	(via
		(at 186.555634 -110.975394)
		(size 0.4572)
		(drill 0.254)
		(layers "F.Cu" "B.Cu")
		(net "JTAG_DBP_BMC_PRDY_R_N")
	)
	(segment
		(start 250.520962 -117.274848)
		(end 267.464286 -117.274848)
		(width 0.127)
		(layer "In15.Cu")
		(net "JTAG_DBP_BMC_PRDY_R_N")
	)
	(segment
		(start 375.985532 -112.977168)
		(end 384.121406 -104.841294)
		(width 0.127)
		(layer "In15.Cu")
		(net "JTAG_DBP_BMC_PRDY_R_N")
	)
	(segment
		(start 189.3697 -110.780068)
		(end 191.9732 -108.176568)
		(width 0.127)
		(layer "In15.Cu")
		(net "JTAG_DBP_BMC_PRDY_R_N")
	)
	(segment
		(start 233.383328 -106.340148)
		(end 240.431828 -113.388648)
		(width 0.127)
		(layer "In15.Cu")
		(net "JTAG_DBP_BMC_PRDY_R_N")
	)
	(segment
		(start 210.679284 -105.662984)
		(end 211.59724 -104.745028)
		(width 0.127)
		(layer "In15.Cu")
		(net "JTAG_DBP_BMC_PRDY_R_N")
	)
	(segment
		(start 187.18022 -110.780068)
		(end 189.3697 -110.780068)
		(width 0.127)
		(layer "In15.Cu")
		(net "JTAG_DBP_BMC_PRDY_R_N")
	)
	(segment
		(start 218.50604 -103.830628)
		(end 221.01556 -106.340148)
		(width 0.127)
		(layer "In15.Cu")
		(net "JTAG_DBP_BMC_PRDY_R_N")
	)
	(segment
		(start 269.153386 -115.585748)
		(end 280.941526 -115.585748)
		(width 0.127)
		(layer "In15.Cu")
		(net "JTAG_DBP_BMC_PRDY_R_N")
	)
	(segment
		(start 206.3115 -108.176568)
		(end 208.825084 -105.662984)
		(width 0.127)
		(layer "In15.Cu")
		(net "JTAG_DBP_BMC_PRDY_R_N")
	)
	(segment
		(start 384.121406 -97.511362)
		(end 380.538736 -93.928692)
		(width 0.127)
		(layer "In15.Cu")
		(net "JTAG_DBP_BMC_PRDY_R_N")
	)
	(segment
		(start 208.825084 -105.662984)
		(end 210.679284 -105.662984)
		(width 0.127)
		(layer "In15.Cu")
		(net "JTAG_DBP_BMC_PRDY_R_N")
	)
	(segment
		(start 283.550106 -112.977168)
		(end 375.985532 -112.977168)
		(width 0.127)
		(layer "In15.Cu")
		(net "JTAG_DBP_BMC_PRDY_R_N")
	)
	(segment
		(start 186.555634 -110.975394)
		(end 186.984894 -110.975394)
		(width 0.127)
		(layer "In15.Cu")
		(net "JTAG_DBP_BMC_PRDY_R_N")
	)
	(segment
		(start 280.941526 -115.585748)
		(end 283.550106 -112.977168)
		(width 0.127)
		(layer "In15.Cu")
		(net "JTAG_DBP_BMC_PRDY_R_N")
	)
	(segment
		(start 384.121406 -104.841294)
		(end 384.121406 -97.511362)
		(width 0.127)
		(layer "In15.Cu")
		(net "JTAG_DBP_BMC_PRDY_R_N")
	)
	(segment
		(start 221.01556 -106.340148)
		(end 233.383328 -106.340148)
		(width 0.127)
		(layer "In15.Cu")
		(net "JTAG_DBP_BMC_PRDY_R_N")
	)
	(segment
		(start 217.32494 -103.830628)
		(end 218.50604 -103.830628)
		(width 0.127)
		(layer "In15.Cu")
		(net "JTAG_DBP_BMC_PRDY_R_N")
	)
	(segment
		(start 216.41054 -104.745028)
		(end 217.32494 -103.830628)
		(width 0.127)
		(layer "In15.Cu")
		(net "JTAG_DBP_BMC_PRDY_R_N")
	)
	(segment
		(start 186.984894 -110.975394)
		(end 187.18022 -110.780068)
		(width 0.127)
		(layer "In15.Cu")
		(net "JTAG_DBP_BMC_PRDY_R_N")
	)
	(segment
		(start 211.59724 -104.745028)
		(end 216.41054 -104.745028)
		(width 0.127)
		(layer "In15.Cu")
		(net "JTAG_DBP_BMC_PRDY_R_N")
	)
	(segment
		(start 267.464286 -117.274848)
		(end 269.153386 -115.585748)
		(width 0.127)
		(layer "In15.Cu")
		(net "JTAG_DBP_BMC_PRDY_R_N")
	)
	(segment
		(start 191.9732 -108.176568)
		(end 206.3115 -108.176568)
		(width 0.127)
		(layer "In15.Cu")
		(net "JTAG_DBP_BMC_PRDY_R_N")
	)
	(segment
		(start 240.431828 -113.388648)
		(end 246.634762 -113.388648)
		(width 0.127)
		(layer "In15.Cu")
		(net "JTAG_DBP_BMC_PRDY_R_N")
	)
	(segment
		(start 246.634762 -113.388648)
		(end 250.520962 -117.274848)
		(width 0.127)
		(layer "In15.Cu")
		(net "JTAG_DBP_BMC_PRDY_R_N")
	)
	(segment
		(start 378.349256 -94.530418)
		(end 378.318522 -94.561152)
		(width 0.12954)
		(layer "F.Cu")
		(net "JTAG_DBP_BMC_PRDY_R1_N")
	)
	(segment
		(start 378.318522 -94.561152)
		(end 378.318522 -96.212152)
		(width 0.12954)
		(layer "F.Cu")
		(net "JTAG_DBP_BMC_PRDY_R1_N")
	)
	(segment
		(start 378.349256 -93.287342)
		(end 378.349256 -94.530418)
		(width 0.12954)
		(layer "F.Cu")
		(net "JTAG_DBP_BMC_PRDY_R1_N")
	)
	(via
		(at 378.318522 -94.561152)
		(size 0.508)
		(drill 0.254)
		(layers "F.Cu" "B.Cu")
		(net "JTAG_DBP_BMC_PRDY_R1_N")
	)
	(segment
		(start 380.538736 -92.487242)
		(end 379.443996 -92.487242)
		(width 0.12954)
		(layer "F.Cu")
		(net "JTAG_DBP_BMC_PRDY_N")
	)
	(segment
		(start 141.746732 -11.773408)
		(end 141.746986 -11.773662)
		(width 0.12954)
		(layer "F.Cu")
		(net "JTAG_DBP_BMC_PRDY_N")
	)
	(segment
		(start 378.349256 -92.487242)
		(end 379.443996 -92.487242)
		(width 0.12954)
		(layer "F.Cu")
		(net "JTAG_DBP_BMC_PRDY_N")
	)
	(segment
		(start 141.746986 -11.773662)
		(end 141.746986 -13.600176)
		(width 0.12954)
		(layer "F.Cu")
		(net "JTAG_DBP_BMC_PRDY_N")
	)
	(segment
		(start 380.538736 -91.877642)
		(end 380.538736 -92.487242)
		(width 0.12954)
		(layer "F.Cu")
		(net "JTAG_DBP_BMC_PRDY_N")
	)
	(via
		(at 380.538736 -91.877642)
		(size 0.508)
		(drill 0.254)
		(layers "F.Cu" "B.Cu")
		(net "JTAG_DBP_BMC_PRDY_N")
	)
	(via
		(at 141.746732 -11.773408)
		(size 0.508)
		(drill 0.254)
		(layers "F.Cu" "B.Cu")
		(net "JTAG_DBP_BMC_PRDY_N")
	)
	(segment
		(start 178.56454 -8.631428)
		(end 183.63184 -13.698728)
		(width 0.127)
		(layer "In13.Cu")
		(net "JTAG_DBP_BMC_PRDY_N")
	)
	(segment
		(start 141.746732 -10.950956)
		(end 142.99946 -9.698228)
		(width 0.127)
		(layer "In13.Cu")
		(net "JTAG_DBP_BMC_PRDY_N")
	)
	(segment
		(start 384.77952 -89.921588)
		(end 382.49479 -89.921588)
		(width 0.127)
		(layer "In13.Cu")
		(net "JTAG_DBP_BMC_PRDY_N")
	)
	(segment
		(start 166.5732 -9.698228)
		(end 167.64 -8.631428)
		(width 0.127)
		(layer "In13.Cu")
		(net "JTAG_DBP_BMC_PRDY_N")
	)
	(segment
		(start 392.192002 -44.87799)
		(end 397.256 -49.941988)
		(width 0.127)
		(layer "In13.Cu")
		(net "JTAG_DBP_BMC_PRDY_N")
	)
	(segment
		(start 211.85632 -19.502628)
		(end 215.6968 -19.502628)
		(width 0.127)
		(layer "In13.Cu")
		(net "JTAG_DBP_BMC_PRDY_N")
	)
	(segment
		(start 194.097656 -13.698728)
		(end 196.25056 -15.851632)
		(width 0.127)
		(layer "In13.Cu")
		(net "JTAG_DBP_BMC_PRDY_N")
	)
	(segment
		(start 397.256 -49.941988)
		(end 397.256 -64.483488)
		(width 0.127)
		(layer "In13.Cu")
		(net "JTAG_DBP_BMC_PRDY_N")
	)
	(segment
		(start 394.94968 -66.789808)
		(end 394.94968 -79.751428)
		(width 0.127)
		(layer "In13.Cu")
		(net "JTAG_DBP_BMC_PRDY_N")
	)
	(segment
		(start 257.55854 -37.216588)
		(end 273.125184 -30.768544)
		(width 0.127)
		(layer "In13.Cu")
		(net "JTAG_DBP_BMC_PRDY_N")
	)
	(segment
		(start 167.64 -8.631428)
		(end 178.56454 -8.631428)
		(width 0.127)
		(layer "In13.Cu")
		(net "JTAG_DBP_BMC_PRDY_N")
	)
	(segment
		(start 223.562164 -37.216588)
		(end 257.55854 -37.216588)
		(width 0.127)
		(layer "In13.Cu")
		(net "JTAG_DBP_BMC_PRDY_N")
	)
	(segment
		(start 215.6968 -19.502628)
		(end 221.178374 -24.984202)
		(width 0.127)
		(layer "In13.Cu")
		(net "JTAG_DBP_BMC_PRDY_N")
	)
	(segment
		(start 397.256 -64.483488)
		(end 394.94968 -66.789808)
		(width 0.127)
		(layer "In13.Cu")
		(net "JTAG_DBP_BMC_PRDY_N")
	)
	(segment
		(start 221.178374 -24.984202)
		(end 221.178374 -34.832798)
		(width 0.127)
		(layer "In13.Cu")
		(net "JTAG_DBP_BMC_PRDY_N")
	)
	(segment
		(start 342.221312 -15.598648)
		(end 358.403906 -22.301708)
		(width 0.127)
		(layer "In13.Cu")
		(net "JTAG_DBP_BMC_PRDY_N")
	)
	(segment
		(start 208.205324 -15.851632)
		(end 211.85632 -19.502628)
		(width 0.127)
		(layer "In13.Cu")
		(net "JTAG_DBP_BMC_PRDY_N")
	)
	(segment
		(start 141.746732 -11.773408)
		(end 141.746732 -10.950956)
		(width 0.127)
		(layer "In13.Cu")
		(net "JTAG_DBP_BMC_PRDY_N")
	)
	(segment
		(start 274.688554 -29.205174)
		(end 307.538882 -15.598648)
		(width 0.127)
		(layer "In13.Cu")
		(net "JTAG_DBP_BMC_PRDY_N")
	)
	(segment
		(start 142.99946 -9.698228)
		(end 166.5732 -9.698228)
		(width 0.127)
		(layer "In13.Cu")
		(net "JTAG_DBP_BMC_PRDY_N")
	)
	(segment
		(start 382.49479 -89.921588)
		(end 380.538736 -91.877642)
		(width 0.127)
		(layer "In13.Cu")
		(net "JTAG_DBP_BMC_PRDY_N")
	)
	(segment
		(start 273.125184 -30.768544)
		(end 274.688554 -29.205174)
		(width 0.127)
		(layer "In13.Cu")
		(net "JTAG_DBP_BMC_PRDY_N")
	)
	(segment
		(start 221.178374 -34.832798)
		(end 223.562164 -37.216588)
		(width 0.127)
		(layer "In13.Cu")
		(net "JTAG_DBP_BMC_PRDY_N")
	)
	(segment
		(start 358.403906 -22.301708)
		(end 392.192002 -44.87799)
		(width 0.127)
		(layer "In13.Cu")
		(net "JTAG_DBP_BMC_PRDY_N")
	)
	(segment
		(start 183.63184 -13.698728)
		(end 194.097656 -13.698728)
		(width 0.127)
		(layer "In13.Cu")
		(net "JTAG_DBP_BMC_PRDY_N")
	)
	(segment
		(start 307.538882 -15.598648)
		(end 342.221312 -15.598648)
		(width 0.127)
		(layer "In13.Cu")
		(net "JTAG_DBP_BMC_PRDY_N")
	)
	(segment
		(start 394.94968 -79.751428)
		(end 384.77952 -89.921588)
		(width 0.127)
		(layer "In13.Cu")
		(net "JTAG_DBP_BMC_PRDY_N")
	)
	(segment
		(start 196.25056 -15.851632)
		(end 208.205324 -15.851632)
		(width 0.127)
		(layer "In13.Cu")
		(net "JTAG_DBP_BMC_PRDY_N")
	)
	(segment
		(start 209.653886 -193.445638)
		(end 211.149184 -193.445638)
		(width 0.12954)
		(layer "F.Cu")
		(net "JTAG_CPU1_MUX_GTL_TDO")
	)
	(segment
		(start 112.110266 -233.87812)
		(end 112.110012 -233.877866)
		(width 0.12954)
		(layer "F.Cu")
		(net "JTAG_CPU1_MUX_GTL_TDO")
	)
	(segment
		(start 152.161748 -190.52286)
		(end 177.81905 -190.52286)
		(width 0.12954)
		(layer "F.Cu")
		(net "JTAG_CPU1_MUX_GTL_TDO")
	)
	(segment
		(start 179.09032 -191.79413)
		(end 207.606138 -191.79413)
		(width 0.12954)
		(layer "F.Cu")
		(net "JTAG_CPU1_MUX_GTL_TDO")
	)
	(segment
		(start 177.81905 -190.52286)
		(end 179.09032 -191.79413)
		(width 0.12954)
		(layer "F.Cu")
		(net "JTAG_CPU1_MUX_GTL_TDO")
	)
	(segment
		(start 209.152998 -192.94475)
		(end 209.653886 -193.445638)
		(width 0.12954)
		(layer "F.Cu")
		(net "JTAG_CPU1_MUX_GTL_TDO")
	)
	(segment
		(start 211.149184 -193.445638)
		(end 211.814918 -192.779904)
		(width 0.12954)
		(layer "F.Cu")
		(net "JTAG_CPU1_MUX_GTL_TDO")
	)
	(segment
		(start 208.756758 -192.94475)
		(end 209.152998 -192.94475)
		(width 0.12954)
		(layer "F.Cu")
		(net "JTAG_CPU1_MUX_GTL_TDO")
	)
	(segment
		(start 112.110012 -233.877866)
		(end 112.110012 -233.34218)
		(width 0.12954)
		(layer "F.Cu")
		(net "JTAG_CPU1_MUX_GTL_TDO")
	)
	(segment
		(start 150.928578 -191.75603)
		(end 152.161748 -190.52286)
		(width 0.12954)
		(layer "F.Cu")
		(net "JTAG_CPU1_MUX_GTL_TDO")
	)
	(segment
		(start 207.606138 -191.79413)
		(end 208.756758 -192.94475)
		(width 0.12954)
		(layer "F.Cu")
		(net "JTAG_CPU1_MUX_GTL_TDO")
	)
	(segment
		(start 91.161108 -191.75603)
		(end 150.928578 -191.75603)
		(width 0.12954)
		(layer "F.Cu")
		(net "JTAG_CPU1_MUX_GTL_TDO")
	)
	(segment
		(start 211.814918 -192.779904)
		(end 212.630258 -192.779904)
		(width 0.12954)
		(layer "F.Cu")
		(net "JTAG_CPU1_MUX_GTL_TDO")
	)
	(via
		(at 112.110012 -233.34218)
		(size 0.4572)
		(drill 0.2032)
		(layers "F.Cu" "B.Cu")
		(net "JTAG_CPU1_MUX_GTL_TDO")
	)
	(via
		(at 91.161108 -191.75603)
		(size 0.508)
		(drill 0.254)
		(layers "F.Cu" "B.Cu")
		(net "JTAG_CPU1_MUX_GTL_TDO")
	)
	(via
		(at 91.161108 -196.431408)
		(size 0.508)
		(drill 0.254)
		(layers "F.Cu" "B.Cu")
		(net "JTAG_CPU1_MUX_GTL_TDO")
	)
	(via
		(at 212.630258 -192.779904)
		(size 0.508)
		(drill 0.254)
		(layers "F.Cu" "B.Cu")
		(net "JTAG_CPU1_MUX_GTL_TDO")
	)
	(segment
		(start 106.096816 -223.575626)
		(end 106.096816 -223.561402)
		(width 0.0889)
		(layer "B.Cu")
		(net "JTAG_CPU1_MUX_GTL_TDO")
	)
	(segment
		(start 101.115368 -221.458282)
		(end 101.106478 -221.453202)
		(width 0.0889)
		(layer "B.Cu")
		(net "JTAG_CPU1_MUX_GTL_TDO")
	)
	(segment
		(start 99.048316 -221.133924)
		(end 99.048316 -221.115382)
		(width 0.0889)
		(layer "B.Cu")
		(net "JTAG_CPU1_MUX_GTL_TDO")
	)
	(segment
		(start 110.043214 -230.41102)
		(end 110.034324 -230.40594)
		(width 0.0889)
		(layer "B.Cu")
		(net "JTAG_CPU1_MUX_GTL_TDO")
	)
	(segment
		(start 95.289116 -221.133924)
		(end 95.289116 -221.115382)
		(width 0.0889)
		(layer "B.Cu")
		(net "JTAG_CPU1_MUX_GTL_TDO")
	)
	(segment
		(start 105.814368 -223.085914)
		(end 105.805478 -223.080834)
		(width 0.0889)
		(layer "B.Cu")
		(net "JTAG_CPU1_MUX_GTL_TDO")
	)
	(segment
		(start 100.645468 -220.644212)
		(end 100.635054 -220.638116)
		(width 0.0889)
		(layer "B.Cu")
		(net "JTAG_CPU1_MUX_GTL_TDO")
	)
	(segment
		(start 103.384096 -221.449646)
		(end 103.369364 -221.458282)
		(width 0.0889)
		(layer "B.Cu")
		(net "JTAG_CPU1_MUX_GTL_TDO")
	)
	(segment
		(start 111.735362 -233.34218)
		(end 111.735362 -233.326686)
		(width 0.0889)
		(layer "B.Cu")
		(net "JTAG_CPU1_MUX_GTL_TDO")
	)
	(segment
		(start 107.506516 -226.017328)
		(end 107.506516 -226.003104)
		(width 0.0889)
		(layer "B.Cu")
		(net "JTAG_CPU1_MUX_GTL_TDO")
	)
	(segment
		(start 85.782658 -218.01709)
		(end 85.782658 -217.64625)
		(width 0.12954)
		(layer "B.Cu")
		(net "JTAG_CPU1_MUX_GTL_TDO")
	)
	(segment
		(start 92.279216 -221.111826)
		(end 92.279216 -221.133924)
		(width 0.0889)
		(layer "B.Cu")
		(net "JTAG_CPU1_MUX_GTL_TDO")
	)
	(segment
		(start 95.476568 -221.458282)
		(end 95.467678 -221.453202)
		(width 0.0889)
		(layer "B.Cu")
		(net "JTAG_CPU1_MUX_GTL_TDO")
	)
	(segment
		(start 95.006668 -220.644212)
		(end 94.996254 -220.638116)
		(width 0.0889)
		(layer "B.Cu")
		(net "JTAG_CPU1_MUX_GTL_TDO")
	)
	(segment
		(start 107.700064 -226.345242)
		(end 107.693968 -226.341686)
		(width 0.0889)
		(layer "B.Cu")
		(net "JTAG_CPU1_MUX_GTL_TDO")
	)
	(segment
		(start 90.399616 -221.111826)
		(end 90.399616 -221.133924)
		(width 0.0889)
		(layer "B.Cu")
		(net "JTAG_CPU1_MUX_GTL_TDO")
	)
	(segment
		(start 109.855762 -230.086662)
		(end 109.855762 -230.071168)
		(width 0.0889)
		(layer "B.Cu")
		(net "JTAG_CPU1_MUX_GTL_TDO")
	)
	(segment
		(start 90.365326 -209.18932)
		(end 92.018866 -207.53578)
		(width 0.12954)
		(layer "B.Cu")
		(net "JTAG_CPU1_MUX_GTL_TDO")
	)
	(segment
		(start 88.350344 -220.584776)
		(end 87.914988 -220.14942)
		(width 0.0889)
		(layer "B.Cu")
		(net "JTAG_CPU1_MUX_GTL_TDO")
	)
	(segment
		(start 108.16971 -228.786944)
		(end 108.163614 -228.783388)
		(width 0.0889)
		(layer "B.Cu")
		(net "JTAG_CPU1_MUX_GTL_TDO")
	)
	(segment
		(start 107.693968 -227.969318)
		(end 107.685078 -227.964238)
		(width 0.0889)
		(layer "B.Cu")
		(net "JTAG_CPU1_MUX_GTL_TDO")
	)
	(segment
		(start 112.110012 -233.34218)
		(end 112.076484 -233.400346)
		(width 0.0889)
		(layer "B.Cu")
		(net "JTAG_CPU1_MUX_GTL_TDO")
	)
	(segment
		(start 111.953548 -233.613198)
		(end 111.949484 -233.614214)
		(width 0.0889)
		(layer "B.Cu")
		(net "JTAG_CPU1_MUX_GTL_TDO")
	)
	(segment
		(start 91.187778 -201.00417)
		(end 91.161108 -200.9775)
		(width 0.12954)
		(layer "B.Cu")
		(net "JTAG_CPU1_MUX_GTL_TDO")
	)
	(segment
		(start 107.036362 -225.203258)
		(end 107.036362 -225.187764)
		(width 0.0889)
		(layer "B.Cu")
		(net "JTAG_CPU1_MUX_GTL_TDO")
	)
	(segment
		(start 90.221054 -221.453202)
		(end 90.212164 -221.458282)
		(width 0.0889)
		(layer "B.Cu")
		(net "JTAG_CPU1_MUX_GTL_TDO")
	)
	(segment
		(start 92.018866 -204.087222)
		(end 91.187778 -203.256134)
		(width 0.12954)
		(layer "B.Cu")
		(net "JTAG_CPU1_MUX_GTL_TDO")
	)
	(segment
		(start 89.919302 -209.18932)
		(end 90.365326 -209.18932)
		(width 0.12954)
		(layer "B.Cu")
		(net "JTAG_CPU1_MUX_GTL_TDO")
	)
	(segment
		(start 110.98911 -232.042462)
		(end 110.983014 -232.038906)
		(width 0.0889)
		(layer "B.Cu")
		(net "JTAG_CPU1_MUX_GTL_TDO")
	)
	(segment
		(start 91.717368 -221.458282)
		(end 91.708478 -221.453202)
		(width 0.0889)
		(layer "B.Cu")
		(net "JTAG_CPU1_MUX_GTL_TDO")
	)
	(segment
		(start 99.235768 -221.458282)
		(end 99.226878 -221.453202)
		(width 0.0889)
		(layer "B.Cu")
		(net "JTAG_CPU1_MUX_GTL_TDO")
	)
	(segment
		(start 107.693968 -227.320602)
		(end 107.700064 -227.317046)
		(width 0.0889)
		(layer "B.Cu")
		(net "JTAG_CPU1_MUX_GTL_TDO")
	)
	(segment
		(start 107.685078 -227.325682)
		(end 107.693968 -227.320602)
		(width 0.0889)
		(layer "B.Cu")
		(net "JTAG_CPU1_MUX_GTL_TDO")
	)
	(segment
		(start 107.976162 -228.45903)
		(end 107.976162 -228.436932)
		(width 0.0889)
		(layer "B.Cu")
		(net "JTAG_CPU1_MUX_GTL_TDO")
	)
	(segment
		(start 91.161108 -200.9775)
		(end 91.161108 -196.431408)
		(width 0.12954)
		(layer "B.Cu")
		(net "JTAG_CPU1_MUX_GTL_TDO")
	)
	(segment
		(start 109.022896 -229.588568)
		(end 109.008164 -229.597204)
		(width 0.0889)
		(layer "B.Cu")
		(net "JTAG_CPU1_MUX_GTL_TDO")
	)
	(segment
		(start 89.837768 -221.458282)
		(end 89.828878 -221.453202)
		(width 0.0889)
		(layer "B.Cu")
		(net "JTAG_CPU1_MUX_GTL_TDO")
	)
	(segment
		(start 111.949484 -233.614214)
		(end 111.875316 -233.634026)
		(width 0.0889)
		(layer "B.Cu")
		(net "JTAG_CPU1_MUX_GTL_TDO")
	)
	(segment
		(start 105.344214 -222.272098)
		(end 105.329482 -222.263462)
		(width 0.0889)
		(layer "B.Cu")
		(net "JTAG_CPU1_MUX_GTL_TDO")
	)
	(segment
		(start 95.859854 -221.453202)
		(end 95.850964 -221.458282)
		(width 0.0889)
		(layer "B.Cu")
		(net "JTAG_CPU1_MUX_GTL_TDO")
	)
	(segment
		(start 93.409516 -221.133924)
		(end 93.409516 -221.115382)
		(width 0.0889)
		(layer "B.Cu")
		(net "JTAG_CPU1_MUX_GTL_TDO")
	)
	(segment
		(start 92.018866 -207.53578)
		(end 92.018866 -204.087222)
		(width 0.12954)
		(layer "B.Cu")
		(net "JTAG_CPU1_MUX_GTL_TDO")
	)
	(segment
		(start 99.619054 -221.453202)
		(end 99.610164 -221.458282)
		(width 0.0889)
		(layer "B.Cu")
		(net "JTAG_CPU1_MUX_GTL_TDO")
	)
	(segment
		(start 213.612476 -192.779904)
		(end 212.630258 -192.779904)
		(width 0.12954)
		(layer "B.Cu")
		(net "JTAG_CPU1_MUX_GTL_TDO")
	)
	(segment
		(start 110.04931 -230.414576)
		(end 110.043214 -230.41102)
		(width 0.0889)
		(layer "B.Cu")
		(net "JTAG_CPU1_MUX_GTL_TDO")
	)
	(segment
		(start 87.914988 -220.14942)
		(end 85.782658 -218.01709)
		(width 0.12954)
		(layer "B.Cu")
		(net "JTAG_CPU1_MUX_GTL_TDO")
	)
	(segment
		(start 107.223814 -225.527616)
		(end 107.214924 -225.522536)
		(width 0.0889)
		(layer "B.Cu")
		(net "JTAG_CPU1_MUX_GTL_TDO")
	)
	(segment
		(start 93.127068 -220.644212)
		(end 93.116654 -220.638116)
		(width 0.0889)
		(layer "B.Cu")
		(net "JTAG_CPU1_MUX_GTL_TDO")
	)
	(segment
		(start 106.754168 -224.7138)
		(end 106.745278 -224.70872)
		(width 0.0889)
		(layer "B.Cu")
		(net "JTAG_CPU1_MUX_GTL_TDO")
	)
	(segment
		(start 100.927916 -221.133924)
		(end 100.927916 -221.115382)
		(width 0.0889)
		(layer "B.Cu")
		(net "JTAG_CPU1_MUX_GTL_TDO")
	)
	(segment
		(start 91.247468 -220.644212)
		(end 91.237054 -220.638116)
		(width 0.0889)
		(layer "B.Cu")
		(net "JTAG_CPU1_MUX_GTL_TDO")
	)
	(segment
		(start 102.807516 -221.133924)
		(end 102.807516 -221.115382)
		(width 0.0889)
		(layer "B.Cu")
		(net "JTAG_CPU1_MUX_GTL_TDO")
	)
	(segment
		(start 97.739454 -221.453202)
		(end 97.730564 -221.458282)
		(width 0.0889)
		(layer "B.Cu")
		(net "JTAG_CPU1_MUX_GTL_TDO")
	)
	(segment
		(start 106.566716 -224.389442)
		(end 106.566716 -224.379536)
		(width 0.0889)
		(layer "B.Cu")
		(net "JTAG_CPU1_MUX_GTL_TDO")
	)
	(segment
		(start 102.994968 -221.458282)
		(end 102.986078 -221.453202)
		(width 0.0889)
		(layer "B.Cu")
		(net "JTAG_CPU1_MUX_GTL_TDO")
	)
	(segment
		(start 108.633768 -229.597204)
		(end 108.624878 -229.592124)
		(width 0.0889)
		(layer "B.Cu")
		(net "JTAG_CPU1_MUX_GTL_TDO")
	)
	(segment
		(start 104.216962 -221.94774)
		(end 104.216962 -221.932246)
		(width 0.0889)
		(layer "B.Cu")
		(net "JTAG_CPU1_MUX_GTL_TDO")
	)
	(segment
		(start 85.40115 -213.707472)
		(end 89.919302 -209.18932)
		(width 0.12954)
		(layer "B.Cu")
		(net "JTAG_CPU1_MUX_GTL_TDO")
	)
	(segment
		(start 91.187778 -203.256134)
		(end 91.187778 -201.00417)
		(width 0.12954)
		(layer "B.Cu")
		(net "JTAG_CPU1_MUX_GTL_TDO")
	)
	(segment
		(start 105.35031 -222.275654)
		(end 105.344214 -222.272098)
		(width 0.0889)
		(layer "B.Cu")
		(net "JTAG_CPU1_MUX_GTL_TDO")
	)
	(segment
		(start 96.886268 -220.644212)
		(end 96.875854 -220.638116)
		(width 0.0889)
		(layer "B.Cu")
		(net "JTAG_CPU1_MUX_GTL_TDO")
	)
	(segment
		(start 93.596968 -221.458282)
		(end 93.588078 -221.453202)
		(width 0.0889)
		(layer "B.Cu")
		(net "JTAG_CPU1_MUX_GTL_TDO")
	)
	(segment
		(start 110.513368 -231.224836)
		(end 110.498382 -231.2162)
		(width 0.0889)
		(layer "B.Cu")
		(net "JTAG_CPU1_MUX_GTL_TDO")
	)
	(segment
		(start 111.453168 -232.852722)
		(end 111.444278 -232.847642)
		(width 0.0889)
		(layer "B.Cu")
		(net "JTAG_CPU1_MUX_GTL_TDO")
	)
	(segment
		(start 97.918016 -221.111826)
		(end 97.918016 -221.133924)
		(width 0.0889)
		(layer "B.Cu")
		(net "JTAG_CPU1_MUX_GTL_TDO")
	)
	(segment
		(start 85.782658 -217.64625)
		(end 85.40115 -217.264742)
		(width 0.12954)
		(layer "B.Cu")
		(net "JTAG_CPU1_MUX_GTL_TDO")
	)
	(segment
		(start 112.076484 -233.400346)
		(end 111.953548 -233.613198)
		(width 0.0889)
		(layer "B.Cu")
		(net "JTAG_CPU1_MUX_GTL_TDO")
	)
	(segment
		(start 91.529916 -221.133924)
		(end 91.529916 -221.115382)
		(width 0.0889)
		(layer "B.Cu")
		(net "JTAG_CPU1_MUX_GTL_TDO")
	)
	(segment
		(start 107.693968 -226.341686)
		(end 107.685078 -226.336606)
		(width 0.0889)
		(layer "B.Cu")
		(net "JTAG_CPU1_MUX_GTL_TDO")
	)
	(segment
		(start 91.161108 -196.431408)
		(end 91.161108 -191.75603)
		(width 0.12954)
		(layer "B.Cu")
		(net "JTAG_CPU1_MUX_GTL_TDO")
	)
	(segment
		(start 93.980254 -221.453202)
		(end 93.971364 -221.458282)
		(width 0.0889)
		(layer "B.Cu")
		(net "JTAG_CPU1_MUX_GTL_TDO")
	)
	(segment
		(start 99.797616 -221.111826)
		(end 99.797616 -221.133924)
		(width 0.0889)
		(layer "B.Cu")
		(net "JTAG_CPU1_MUX_GTL_TDO")
	)
	(segment
		(start 101.677216 -221.111826)
		(end 101.677216 -221.133924)
		(width 0.0889)
		(layer "B.Cu")
		(net "JTAG_CPU1_MUX_GTL_TDO")
	)
	(segment
		(start 97.168716 -221.133924)
		(end 97.168716 -221.115382)
		(width 0.0889)
		(layer "B.Cu")
		(net "JTAG_CPU1_MUX_GTL_TDO")
	)
	(segment
		(start 96.038416 -221.111826)
		(end 96.038416 -221.133924)
		(width 0.0889)
		(layer "B.Cu")
		(net "JTAG_CPU1_MUX_GTL_TDO")
	)
	(segment
		(start 110.795816 -231.723184)
		(end 110.795816 -231.696006)
		(width 0.0889)
		(layer "B.Cu")
		(net "JTAG_CPU1_MUX_GTL_TDO")
	)
	(segment
		(start 98.765868 -220.644212)
		(end 98.755454 -220.638116)
		(width 0.0889)
		(layer "B.Cu")
		(net "JTAG_CPU1_MUX_GTL_TDO")
	)
	(segment
		(start 104.404414 -222.272098)
		(end 104.395524 -222.267018)
		(width 0.0889)
		(layer "B.Cu")
		(net "JTAG_CPU1_MUX_GTL_TDO")
	)
	(segment
		(start 92.100654 -221.453202)
		(end 92.091764 -221.458282)
		(width 0.0889)
		(layer "B.Cu")
		(net "JTAG_CPU1_MUX_GTL_TDO")
	)
	(segment
		(start 108.163614 -228.783388)
		(end 108.154724 -228.778308)
		(width 0.0889)
		(layer "B.Cu")
		(net "JTAG_CPU1_MUX_GTL_TDO")
	)
	(segment
		(start 97.356168 -221.458282)
		(end 97.347278 -221.453202)
		(width 0.0889)
		(layer "B.Cu")
		(net "JTAG_CPU1_MUX_GTL_TDO")
	)
	(segment
		(start 106.284268 -223.899984)
		(end 106.275378 -223.894904)
		(width 0.0889)
		(layer "B.Cu")
		(net "JTAG_CPU1_MUX_GTL_TDO")
	)
	(segment
		(start 102.525068 -220.644212)
		(end 102.514654 -220.638116)
		(width 0.0889)
		(layer "B.Cu")
		(net "JTAG_CPU1_MUX_GTL_TDO")
	)
	(segment
		(start 85.40115 -217.264742)
		(end 85.40115 -213.707472)
		(width 0.12954)
		(layer "B.Cu")
		(net "JTAG_CPU1_MUX_GTL_TDO")
	)
	(segment
		(start 94.158816 -221.111826)
		(end 94.158816 -221.133924)
		(width 0.0889)
		(layer "B.Cu")
		(net "JTAG_CPU1_MUX_GTL_TDO")
	)
	(segment
		(start 101.498654 -221.453202)
		(end 101.489764 -221.458282)
		(width 0.0889)
		(layer "B.Cu")
		(net "JTAG_CPU1_MUX_GTL_TDO")
	)
	(segment
		(start 89.650316 -221.133924)
		(end 89.650316 -221.115382)
		(width 0.0889)
		(layer "B.Cu")
		(net "JTAG_CPU1_MUX_GTL_TDO")
	)
	(segment
		(start 91.161108 -191.75603)
		(end 91.161108 -191.105282)
		(width 0.12954)
		(layer "B.Cu")
		(net "JTAG_CPU1_MUX_GTL_TDO")
	)
	(arc
		(start 107.685078 -227.964238)
		(mid 107.682404 -227.962598)
		(end 107.679744 -227.960936)
		(width 0.0889)
		(layer "B.Cu")
		(net "JTAG_CPU1_MUX_GTL_TDO")
	)
	(arc
		(start 103.369364 -221.458282)
		(mid 103.182166 -221.508425)
		(end 102.994968 -221.458282)
		(width 0.0889)
		(layer "B.Cu")
		(net "JTAG_CPU1_MUX_GTL_TDO")
	)
	(arc
		(start 101.106478 -221.453202)
		(mid 100.975564 -221.316842)
		(end 100.927916 -221.133924)
		(width 0.0889)
		(layer "B.Cu")
		(net "JTAG_CPU1_MUX_GTL_TDO")
	)
	(arc
		(start 100.07981 -220.644212)
		(mid 99.878528 -220.841699)
		(end 99.797616 -221.111826)
		(width 0.0889)
		(layer "B.Cu")
		(net "JTAG_CPU1_MUX_GTL_TDO")
	)
	(arc
		(start 99.610164 -221.458282)
		(mid 99.422966 -221.508425)
		(end 99.235768 -221.458282)
		(width 0.0889)
		(layer "B.Cu")
		(net "JTAG_CPU1_MUX_GTL_TDO")
	)
	(arc
		(start 107.214924 -225.522536)
		(mid 107.08401 -225.386176)
		(end 107.036362 -225.203258)
		(width 0.0889)
		(layer "B.Cu")
		(net "JTAG_CPU1_MUX_GTL_TDO")
	)
	(arc
		(start 89.828878 -221.453202)
		(mid 89.697964 -221.316842)
		(end 89.650316 -221.133924)
		(width 0.0889)
		(layer "B.Cu")
		(net "JTAG_CPU1_MUX_GTL_TDO")
	)
	(arc
		(start 105.626916 -222.761556)
		(mid 105.552925 -222.48199)
		(end 105.35031 -222.275654)
		(width 0.0889)
		(layer "B.Cu")
		(net "JTAG_CPU1_MUX_GTL_TDO")
	)
	(arc
		(start 88.802464 -220.644212)
		(mid 88.615266 -220.694355)
		(end 88.428068 -220.644212)
		(width 0.0889)
		(layer "B.Cu")
		(net "JTAG_CPU1_MUX_GTL_TDO")
	)
	(arc
		(start 104.216962 -221.932246)
		(mid 104.137592 -221.658512)
		(end 103.934768 -221.458282)
		(width 0.0889)
		(layer "B.Cu")
		(net "JTAG_CPU1_MUX_GTL_TDO")
	)
	(arc
		(start 95.289116 -221.115382)
		(mid 95.208954 -220.843193)
		(end 95.006668 -220.644212)
		(width 0.0889)
		(layer "B.Cu")
		(net "JTAG_CPU1_MUX_GTL_TDO")
	)
	(arc
		(start 90.68181 -220.644212)
		(mid 90.480528 -220.841699)
		(end 90.399616 -221.111826)
		(width 0.0889)
		(layer "B.Cu")
		(net "JTAG_CPU1_MUX_GTL_TDO")
	)
	(arc
		(start 97.918016 -221.133924)
		(mid 97.870337 -221.316824)
		(end 97.739454 -221.453202)
		(width 0.0889)
		(layer "B.Cu")
		(net "JTAG_CPU1_MUX_GTL_TDO")
	)
	(arc
		(start 91.708478 -221.453202)
		(mid 91.577564 -221.316842)
		(end 91.529916 -221.133924)
		(width 0.0889)
		(layer "B.Cu")
		(net "JTAG_CPU1_MUX_GTL_TDO")
	)
	(arc
		(start 107.700064 -227.317046)
		(mid 107.97639 -226.831144)
		(end 107.700064 -226.345242)
		(width 0.0889)
		(layer "B.Cu")
		(net "JTAG_CPU1_MUX_GTL_TDO")
	)
	(arc
		(start 104.77881 -222.272098)
		(mid 104.591612 -222.322241)
		(end 104.404414 -222.272098)
		(width 0.0889)
		(layer "B.Cu")
		(net "JTAG_CPU1_MUX_GTL_TDO")
	)
	(arc
		(start 109.008164 -229.597204)
		(mid 108.820966 -229.647347)
		(end 108.633768 -229.597204)
		(width 0.0889)
		(layer "B.Cu")
		(net "JTAG_CPU1_MUX_GTL_TDO")
	)
	(arc
		(start 107.679744 -227.960936)
		(mid 107.552701 -227.82512)
		(end 107.506516 -227.64496)
		(width 0.0889)
		(layer "B.Cu")
		(net "JTAG_CPU1_MUX_GTL_TDO")
	)
	(arc
		(start 90.399616 -221.133924)
		(mid 90.351937 -221.316824)
		(end 90.221054 -221.453202)
		(width 0.0889)
		(layer "B.Cu")
		(net "JTAG_CPU1_MUX_GTL_TDO")
	)
	(arc
		(start 103.934768 -221.458282)
		(mid 103.660569 -221.382447)
		(end 103.384096 -221.449646)
		(width 0.0889)
		(layer "B.Cu")
		(net "JTAG_CPU1_MUX_GTL_TDO")
	)
	(arc
		(start 101.95941 -220.644212)
		(mid 101.758128 -220.841699)
		(end 101.677216 -221.111826)
		(width 0.0889)
		(layer "B.Cu")
		(net "JTAG_CPU1_MUX_GTL_TDO")
	)
	(arc
		(start 110.795816 -231.696006)
		(mid 110.715654 -231.423817)
		(end 110.513368 -231.224836)
		(width 0.0889)
		(layer "B.Cu")
		(net "JTAG_CPU1_MUX_GTL_TDO")
	)
	(arc
		(start 110.983014 -232.038906)
		(mid 110.848081 -231.905552)
		(end 110.795816 -231.723184)
		(width 0.0889)
		(layer "B.Cu")
		(net "JTAG_CPU1_MUX_GTL_TDO")
	)
	(arc
		(start 99.797616 -221.133924)
		(mid 99.749937 -221.316824)
		(end 99.619054 -221.453202)
		(width 0.0889)
		(layer "B.Cu")
		(net "JTAG_CPU1_MUX_GTL_TDO")
	)
	(arc
		(start 108.154724 -228.778308)
		(mid 108.02381 -228.641948)
		(end 107.976162 -228.45903)
		(width 0.0889)
		(layer "B.Cu")
		(net "JTAG_CPU1_MUX_GTL_TDO")
	)
	(arc
		(start 92.279216 -221.133924)
		(mid 92.231537 -221.316824)
		(end 92.100654 -221.453202)
		(width 0.0889)
		(layer "B.Cu")
		(net "JTAG_CPU1_MUX_GTL_TDO")
	)
	(arc
		(start 107.976162 -228.436932)
		(mid 107.895251 -228.166804)
		(end 107.693968 -227.969318)
		(width 0.0889)
		(layer "B.Cu")
		(net "JTAG_CPU1_MUX_GTL_TDO")
	)
	(arc
		(start 110.034324 -230.40594)
		(mid 109.90341 -230.26958)
		(end 109.855762 -230.086662)
		(width 0.0889)
		(layer "B.Cu")
		(net "JTAG_CPU1_MUX_GTL_TDO")
	)
	(arc
		(start 99.226878 -221.453202)
		(mid 99.095964 -221.316842)
		(end 99.048316 -221.133924)
		(width 0.0889)
		(layer "B.Cu")
		(net "JTAG_CPU1_MUX_GTL_TDO")
	)
	(arc
		(start 96.32061 -220.644212)
		(mid 96.119328 -220.841699)
		(end 96.038416 -221.111826)
		(width 0.0889)
		(layer "B.Cu")
		(net "JTAG_CPU1_MUX_GTL_TDO")
	)
	(arc
		(start 97.730564 -221.458282)
		(mid 97.543366 -221.508425)
		(end 97.356168 -221.458282)
		(width 0.0889)
		(layer "B.Cu")
		(net "JTAG_CPU1_MUX_GTL_TDO")
	)
	(arc
		(start 91.237054 -220.638116)
		(mid 90.958622 -220.568302)
		(end 90.68181 -220.644212)
		(width 0.0889)
		(layer "B.Cu")
		(net "JTAG_CPU1_MUX_GTL_TDO")
	)
	(arc
		(start 92.091764 -221.458282)
		(mid 91.904566 -221.508425)
		(end 91.717368 -221.458282)
		(width 0.0889)
		(layer "B.Cu")
		(net "JTAG_CPU1_MUX_GTL_TDO")
	)
	(arc
		(start 101.677216 -221.133924)
		(mid 101.629537 -221.316824)
		(end 101.498654 -221.453202)
		(width 0.0889)
		(layer "B.Cu")
		(net "JTAG_CPU1_MUX_GTL_TDO")
	)
	(arc
		(start 107.685078 -226.336606)
		(mid 107.554164 -226.200246)
		(end 107.506516 -226.017328)
		(width 0.0889)
		(layer "B.Cu")
		(net "JTAG_CPU1_MUX_GTL_TDO")
	)
	(arc
		(start 105.329482 -222.263462)
		(mid 105.053007 -222.196142)
		(end 104.77881 -222.272098)
		(width 0.0889)
		(layer "B.Cu")
		(net "JTAG_CPU1_MUX_GTL_TDO")
	)
	(arc
		(start 102.514654 -220.638116)
		(mid 102.236222 -220.568302)
		(end 101.95941 -220.644212)
		(width 0.0889)
		(layer "B.Cu")
		(net "JTAG_CPU1_MUX_GTL_TDO")
	)
	(arc
		(start 96.038416 -221.133924)
		(mid 95.990737 -221.316824)
		(end 95.859854 -221.453202)
		(width 0.0889)
		(layer "B.Cu")
		(net "JTAG_CPU1_MUX_GTL_TDO")
	)
	(arc
		(start 90.212164 -221.458282)
		(mid 90.024966 -221.508425)
		(end 89.837768 -221.458282)
		(width 0.0889)
		(layer "B.Cu")
		(net "JTAG_CPU1_MUX_GTL_TDO")
	)
	(arc
		(start 106.096816 -223.561402)
		(mid 106.017675 -223.286779)
		(end 105.814368 -223.085914)
		(width 0.0889)
		(layer "B.Cu")
		(net "JTAG_CPU1_MUX_GTL_TDO")
	)
	(arc
		(start 92.56141 -220.644212)
		(mid 92.360128 -220.841699)
		(end 92.279216 -221.111826)
		(width 0.0889)
		(layer "B.Cu")
		(net "JTAG_CPU1_MUX_GTL_TDO")
	)
	(arc
		(start 93.588078 -221.453202)
		(mid 93.457164 -221.316842)
		(end 93.409516 -221.133924)
		(width 0.0889)
		(layer "B.Cu")
		(net "JTAG_CPU1_MUX_GTL_TDO")
	)
	(arc
		(start 98.755454 -220.638116)
		(mid 98.477022 -220.568302)
		(end 98.20021 -220.644212)
		(width 0.0889)
		(layer "B.Cu")
		(net "JTAG_CPU1_MUX_GTL_TDO")
	)
	(arc
		(start 110.325662 -230.900478)
		(mid 110.251746 -230.620976)
		(end 110.04931 -230.414576)
		(width 0.0889)
		(layer "B.Cu")
		(net "JTAG_CPU1_MUX_GTL_TDO")
	)
	(arc
		(start 111.265716 -232.528364)
		(mid 111.191725 -232.248798)
		(end 110.98911 -232.042462)
		(width 0.0889)
		(layer "B.Cu")
		(net "JTAG_CPU1_MUX_GTL_TDO")
	)
	(arc
		(start 101.489764 -221.458282)
		(mid 101.302566 -221.508425)
		(end 101.115368 -221.458282)
		(width 0.0889)
		(layer "B.Cu")
		(net "JTAG_CPU1_MUX_GTL_TDO")
	)
	(arc
		(start 97.347278 -221.453202)
		(mid 97.216364 -221.316842)
		(end 97.168716 -221.133924)
		(width 0.0889)
		(layer "B.Cu")
		(net "JTAG_CPU1_MUX_GTL_TDO")
	)
	(arc
		(start 94.158816 -221.133924)
		(mid 94.111137 -221.316824)
		(end 93.980254 -221.453202)
		(width 0.0889)
		(layer "B.Cu")
		(net "JTAG_CPU1_MUX_GTL_TDO")
	)
	(arc
		(start 106.275378 -223.894904)
		(mid 106.144464 -223.758544)
		(end 106.096816 -223.575626)
		(width 0.0889)
		(layer "B.Cu")
		(net "JTAG_CPU1_MUX_GTL_TDO")
	)
	(arc
		(start 107.506516 -226.003104)
		(mid 107.427297 -225.728419)
		(end 107.223814 -225.527616)
		(width 0.0889)
		(layer "B.Cu")
		(net "JTAG_CPU1_MUX_GTL_TDO")
	)
	(arc
		(start 93.409516 -221.115382)
		(mid 93.329354 -220.843193)
		(end 93.127068 -220.644212)
		(width 0.0889)
		(layer "B.Cu")
		(net "JTAG_CPU1_MUX_GTL_TDO")
	)
	(arc
		(start 94.44101 -220.644212)
		(mid 94.239728 -220.841699)
		(end 94.158816 -221.111826)
		(width 0.0889)
		(layer "B.Cu")
		(net "JTAG_CPU1_MUX_GTL_TDO")
	)
	(arc
		(start 100.927916 -221.115382)
		(mid 100.847754 -220.843193)
		(end 100.645468 -220.644212)
		(width 0.0889)
		(layer "B.Cu")
		(net "JTAG_CPU1_MUX_GTL_TDO")
	)
	(arc
		(start 109.573568 -229.597204)
		(mid 109.299369 -229.521369)
		(end 109.022896 -229.588568)
		(width 0.0889)
		(layer "B.Cu")
		(net "JTAG_CPU1_MUX_GTL_TDO")
	)
	(arc
		(start 99.048316 -221.115382)
		(mid 98.968154 -220.843193)
		(end 98.765868 -220.644212)
		(width 0.0889)
		(layer "B.Cu")
		(net "JTAG_CPU1_MUX_GTL_TDO")
	)
	(arc
		(start 97.168716 -221.115382)
		(mid 97.088554 -220.843193)
		(end 96.886268 -220.644212)
		(width 0.0889)
		(layer "B.Cu")
		(net "JTAG_CPU1_MUX_GTL_TDO")
	)
	(arc
		(start 106.745278 -224.70872)
		(mid 106.614364 -224.57236)
		(end 106.566716 -224.389442)
		(width 0.0889)
		(layer "B.Cu")
		(net "JTAG_CPU1_MUX_GTL_TDO")
	)
	(arc
		(start 98.20021 -220.644212)
		(mid 97.998928 -220.841699)
		(end 97.918016 -221.111826)
		(width 0.0889)
		(layer "B.Cu")
		(net "JTAG_CPU1_MUX_GTL_TDO")
	)
	(arc
		(start 104.395524 -222.267018)
		(mid 104.26461 -222.130658)
		(end 104.216962 -221.94774)
		(width 0.0889)
		(layer "B.Cu")
		(net "JTAG_CPU1_MUX_GTL_TDO")
	)
	(arc
		(start 95.850964 -221.458282)
		(mid 95.663766 -221.508425)
		(end 95.476568 -221.458282)
		(width 0.0889)
		(layer "B.Cu")
		(net "JTAG_CPU1_MUX_GTL_TDO")
	)
	(arc
		(start 91.529916 -221.115382)
		(mid 91.449754 -220.843193)
		(end 91.247468 -220.644212)
		(width 0.0889)
		(layer "B.Cu")
		(net "JTAG_CPU1_MUX_GTL_TDO")
	)
	(arc
		(start 100.635054 -220.638116)
		(mid 100.356622 -220.568302)
		(end 100.07981 -220.644212)
		(width 0.0889)
		(layer "B.Cu")
		(net "JTAG_CPU1_MUX_GTL_TDO")
	)
	(arc
		(start 96.875854 -220.638116)
		(mid 96.597422 -220.568302)
		(end 96.32061 -220.644212)
		(width 0.0889)
		(layer "B.Cu")
		(net "JTAG_CPU1_MUX_GTL_TDO")
	)
	(arc
		(start 102.986078 -221.453202)
		(mid 102.855164 -221.316842)
		(end 102.807516 -221.133924)
		(width 0.0889)
		(layer "B.Cu")
		(net "JTAG_CPU1_MUX_GTL_TDO")
	)
	(arc
		(start 102.807516 -221.115382)
		(mid 102.727354 -220.843193)
		(end 102.525068 -220.644212)
		(width 0.0889)
		(layer "B.Cu")
		(net "JTAG_CPU1_MUX_GTL_TDO")
	)
	(arc
		(start 109.855762 -230.071168)
		(mid 109.776392 -229.797434)
		(end 109.573568 -229.597204)
		(width 0.0889)
		(layer "B.Cu")
		(net "JTAG_CPU1_MUX_GTL_TDO")
	)
	(arc
		(start 106.566716 -224.379536)
		(mid 106.488605 -224.102587)
		(end 106.284268 -223.899984)
		(width 0.0889)
		(layer "B.Cu")
		(net "JTAG_CPU1_MUX_GTL_TDO")
	)
	(arc
		(start 111.735362 -233.326686)
		(mid 111.655992 -233.052952)
		(end 111.453168 -232.852722)
		(width 0.0889)
		(layer "B.Cu")
		(net "JTAG_CPU1_MUX_GTL_TDO")
	)
	(arc
		(start 108.624878 -229.592124)
		(mid 108.493964 -229.455764)
		(end 108.446316 -229.272846)
		(width 0.0889)
		(layer "B.Cu")
		(net "JTAG_CPU1_MUX_GTL_TDO")
	)
	(arc
		(start 93.971364 -221.458282)
		(mid 93.784166 -221.508425)
		(end 93.596968 -221.458282)
		(width 0.0889)
		(layer "B.Cu")
		(net "JTAG_CPU1_MUX_GTL_TDO")
	)
	(arc
		(start 107.036362 -225.187764)
		(mid 106.956992 -224.91403)
		(end 106.754168 -224.7138)
		(width 0.0889)
		(layer "B.Cu")
		(net "JTAG_CPU1_MUX_GTL_TDO")
	)
	(arc
		(start 107.506516 -227.64496)
		(mid 107.554195 -227.46206)
		(end 107.685078 -227.325682)
		(width 0.0889)
		(layer "B.Cu")
		(net "JTAG_CPU1_MUX_GTL_TDO")
	)
	(arc
		(start 89.650316 -221.115382)
		(mid 89.570154 -220.843193)
		(end 89.367868 -220.644212)
		(width 0.0889)
		(layer "B.Cu")
		(net "JTAG_CPU1_MUX_GTL_TDO")
	)
	(arc
		(start 111.875316 -233.634026)
		(mid 111.772171 -233.504001)
		(end 111.735362 -233.34218)
		(width 0.0889)
		(layer "B.Cu")
		(net "JTAG_CPU1_MUX_GTL_TDO")
	)
	(arc
		(start 105.805478 -223.080834)
		(mid 105.674564 -222.944474)
		(end 105.626916 -222.761556)
		(width 0.0889)
		(layer "B.Cu")
		(net "JTAG_CPU1_MUX_GTL_TDO")
	)
	(arc
		(start 89.367868 -220.644212)
		(mid 89.085166 -220.56847)
		(end 88.802464 -220.644212)
		(width 0.0889)
		(layer "B.Cu")
		(net "JTAG_CPU1_MUX_GTL_TDO")
	)
	(arc
		(start 108.446316 -229.272846)
		(mid 108.372325 -228.99328)
		(end 108.16971 -228.786944)
		(width 0.0889)
		(layer "B.Cu")
		(net "JTAG_CPU1_MUX_GTL_TDO")
	)
	(arc
		(start 93.116654 -220.638116)
		(mid 92.838222 -220.568302)
		(end 92.56141 -220.644212)
		(width 0.0889)
		(layer "B.Cu")
		(net "JTAG_CPU1_MUX_GTL_TDO")
	)
	(arc
		(start 88.428068 -220.644212)
		(mid 88.387259 -220.61704)
		(end 88.350344 -220.584776)
		(width 0.0889)
		(layer "B.Cu")
		(net "JTAG_CPU1_MUX_GTL_TDO")
	)
	(arc
		(start 110.498382 -231.2162)
		(mid 110.371659 -231.080419)
		(end 110.325662 -230.900478)
		(width 0.0889)
		(layer "B.Cu")
		(net "JTAG_CPU1_MUX_GTL_TDO")
	)
	(arc
		(start 94.996254 -220.638116)
		(mid 94.717822 -220.568302)
		(end 94.44101 -220.644212)
		(width 0.0889)
		(layer "B.Cu")
		(net "JTAG_CPU1_MUX_GTL_TDO")
	)
	(arc
		(start 95.467678 -221.453202)
		(mid 95.336764 -221.316842)
		(end 95.289116 -221.133924)
		(width 0.0889)
		(layer "B.Cu")
		(net "JTAG_CPU1_MUX_GTL_TDO")
	)
	(arc
		(start 111.444278 -232.847642)
		(mid 111.313364 -232.711282)
		(end 111.265716 -232.528364)
		(width 0.0889)
		(layer "B.Cu")
		(net "JTAG_CPU1_MUX_GTL_TDO")
	)
	(segment
		(start 360.050334 -233.87812)
		(end 360.05008 -233.877866)
		(width 0.12954)
		(layer "F.Cu")
		(net "JTAG_CPU0_MUX_GTL_TDO")
	)
	(segment
		(start 228.82352 -187.782708)
		(end 226.24796 -187.782708)
		(width 0.12954)
		(layer "F.Cu")
		(net "JTAG_CPU0_MUX_GTL_TDO")
	)
	(segment
		(start 270.93672 -159.962088)
		(end 270.93672 -167.490648)
		(width 0.12954)
		(layer "F.Cu")
		(net "JTAG_CPU0_MUX_GTL_TDO")
	)
	(segment
		(start 267.12672 -156.152088)
		(end 270.93672 -159.962088)
		(width 0.12954)
		(layer "F.Cu")
		(net "JTAG_CPU0_MUX_GTL_TDO")
	)
	(segment
		(start 246.51208 -170.094148)
		(end 228.82352 -187.782708)
		(width 0.12954)
		(layer "F.Cu")
		(net "JTAG_CPU0_MUX_GTL_TDO")
	)
	(segment
		(start 270.93672 -167.490648)
		(end 268.33322 -170.094148)
		(width 0.12954)
		(layer "F.Cu")
		(net "JTAG_CPU0_MUX_GTL_TDO")
	)
	(segment
		(start 268.33322 -170.094148)
		(end 246.51208 -170.094148)
		(width 0.12954)
		(layer "F.Cu")
		(net "JTAG_CPU0_MUX_GTL_TDO")
	)
	(segment
		(start 360.05008 -233.877866)
		(end 360.05008 -233.34218)
		(width 0.12954)
		(layer "F.Cu")
		(net "JTAG_CPU0_MUX_GTL_TDO")
	)
	(segment
		(start 226.24796 -187.782708)
		(end 225.806 -187.340748)
		(width 0.12954)
		(layer "F.Cu")
		(net "JTAG_CPU0_MUX_GTL_TDO")
	)
	(via
		(at 213.824058 -194.76593)
		(size 0.508)
		(drill 0.254)
		(layers "F.Cu" "B.Cu")
		(net "JTAG_CPU0_MUX_GTL_TDO")
	)
	(via
		(at 331.543152 -217.958416)
		(size 0.7112)
		(drill 0.3556)
		(layers "F.Cu" "B.Cu")
		(net "JTAG_CPU0_MUX_GTL_TDO")
	)
	(via
		(at 225.806 -187.340748)
		(size 0.508)
		(drill 0.254)
		(layers "F.Cu" "B.Cu")
		(net "JTAG_CPU0_MUX_GTL_TDO")
	)
	(via
		(at 360.05008 -233.34218)
		(size 0.4572)
		(drill 0.2032)
		(layers "F.Cu" "B.Cu")
		(net "JTAG_CPU0_MUX_GTL_TDO")
	)
	(via
		(at 267.12672 -156.152088)
		(size 0.508)
		(drill 0.254)
		(layers "F.Cu" "B.Cu")
		(net "JTAG_CPU0_MUX_GTL_TDO")
	)
	(segment
		(start 217.324178 -194.89801)
		(end 217.324178 -194.45605)
		(width 0.12954)
		(layer "B.Cu")
		(net "JTAG_CPU0_MUX_GTL_TDO")
	)
	(segment
		(start 217.324178 -194.45605)
		(end 217.166698 -194.29857)
		(width 0.12954)
		(layer "B.Cu")
		(net "JTAG_CPU0_MUX_GTL_TDO")
	)
	(segment
		(start 327.082658 -213.497922)
		(end 331.543152 -217.958416)
		(width 0.12954)
		(layer "B.Cu")
		(net "JTAG_CPU0_MUX_GTL_TDO")
	)
	(segment
		(start 357.79583 -230.071168)
		(end 357.79583 -230.086662)
		(width 0.0889)
		(layer "B.Cu")
		(net "JTAG_CPU0_MUX_GTL_TDO")
	)
	(segment
		(start 359.815384 -233.634026)
		(end 359.893616 -233.613198)
		(width 0.0889)
		(layer "B.Cu")
		(net "JTAG_CPU0_MUX_GTL_TDO")
	)
	(segment
		(start 345.75115 -222.263462)
		(end 345.765882 -222.272098)
		(width 0.0889)
		(layer "B.Cu")
		(net "JTAG_CPU0_MUX_GTL_TDO")
	)
	(segment
		(start 350.45015 -222.263462)
		(end 350.464882 -222.272098)
		(width 0.0889)
		(layer "B.Cu")
		(net "JTAG_CPU0_MUX_GTL_TDO")
	)
	(segment
		(start 340.11235 -222.263462)
		(end 340.127082 -222.272098)
		(width 0.0889)
		(layer "B.Cu")
		(net "JTAG_CPU0_MUX_GTL_TDO")
	)
	(segment
		(start 354.036884 -223.561402)
		(end 354.036884 -223.575626)
		(width 0.0889)
		(layer "B.Cu")
		(net "JTAG_CPU0_MUX_GTL_TDO")
	)
	(segment
		(start 359.67543 -233.326686)
		(end 359.67543 -233.34218)
		(width 0.0889)
		(layer "B.Cu")
		(net "JTAG_CPU0_MUX_GTL_TDO")
	)
	(segment
		(start 310.638698 -166.96563)
		(end 327.10374 -183.430672)
		(width 0.12954)
		(layer "B.Cu")
		(net "JTAG_CPU0_MUX_GTL_TDO")
	)
	(segment
		(start 327.613518 -188.21273)
		(end 328.405998 -189.00521)
		(width 0.12954)
		(layer "B.Cu")
		(net "JTAG_CPU0_MUX_GTL_TDO")
	)
	(segment
		(start 341.05215 -222.263462)
		(end 341.066882 -222.272098)
		(width 0.0889)
		(layer "B.Cu")
		(net "JTAG_CPU0_MUX_GTL_TDO")
	)
	(segment
		(start 355.640132 -227.317046)
		(end 355.625146 -227.325682)
		(width 0.0889)
		(layer "B.Cu")
		(net "JTAG_CPU0_MUX_GTL_TDO")
	)
	(segment
		(start 213.824058 -194.76593)
		(end 213.612476 -194.554348)
		(width 0.12954)
		(layer "B.Cu")
		(net "JTAG_CPU0_MUX_GTL_TDO")
	)
	(segment
		(start 347.63075 -222.263462)
		(end 347.645482 -222.272098)
		(width 0.0889)
		(layer "B.Cu")
		(net "JTAG_CPU0_MUX_GTL_TDO")
	)
	(segment
		(start 343.87155 -222.263462)
		(end 343.886282 -222.272098)
		(width 0.0889)
		(layer "B.Cu")
		(net "JTAG_CPU0_MUX_GTL_TDO")
	)
	(segment
		(start 277.940262 -166.96563)
		(end 310.638698 -166.96563)
		(width 0.12954)
		(layer "B.Cu")
		(net "JTAG_CPU0_MUX_GTL_TDO")
	)
	(segment
		(start 331.543152 -217.958416)
		(end 334.941926 -221.35719)
		(width 0.12954)
		(layer "B.Cu")
		(net "JTAG_CPU0_MUX_GTL_TDO")
	)
	(segment
		(start 355.625146 -226.336606)
		(end 355.640132 -226.345242)
		(width 0.0889)
		(layer "B.Cu")
		(net "JTAG_CPU0_MUX_GTL_TDO")
	)
	(segment
		(start 341.99195 -222.263462)
		(end 342.006682 -222.272098)
		(width 0.0889)
		(layer "B.Cu")
		(net "JTAG_CPU0_MUX_GTL_TDO")
	)
	(segment
		(start 213.612476 -194.554348)
		(end 213.612476 -194.079876)
		(width 0.12954)
		(layer "B.Cu")
		(net "JTAG_CPU0_MUX_GTL_TDO")
	)
	(segment
		(start 358.735884 -231.696006)
		(end 358.735884 -231.723184)
		(width 0.0889)
		(layer "B.Cu")
		(net "JTAG_CPU0_MUX_GTL_TDO")
	)
	(segment
		(start 218.2114 -195.36791)
		(end 217.794078 -195.36791)
		(width 0.12954)
		(layer "B.Cu")
		(net "JTAG_CPU0_MUX_GTL_TDO")
	)
	(segment
		(start 354.215446 -223.894904)
		(end 354.224336 -223.899984)
		(width 0.0889)
		(layer "B.Cu")
		(net "JTAG_CPU0_MUX_GTL_TDO")
	)
	(segment
		(start 328.405998 -189.00521)
		(end 328.405998 -191.66459)
		(width 0.12954)
		(layer "B.Cu")
		(net "JTAG_CPU0_MUX_GTL_TDO")
	)
	(segment
		(start 354.685346 -224.70872)
		(end 354.694236 -224.7138)
		(width 0.0889)
		(layer "B.Cu")
		(net "JTAG_CPU0_MUX_GTL_TDO")
	)
	(segment
		(start 267.12672 -156.152088)
		(end 277.940262 -166.96563)
		(width 0.12954)
		(layer "B.Cu")
		(net "JTAG_CPU0_MUX_GTL_TDO")
	)
	(segment
		(start 214.212678 -194.079876)
		(end 213.612476 -194.079876)
		(width 0.12954)
		(layer "B.Cu")
		(net "JTAG_CPU0_MUX_GTL_TDO")
	)
	(segment
		(start 355.154992 -225.522536)
		(end 355.163882 -225.527616)
		(width 0.0889)
		(layer "B.Cu")
		(net "JTAG_CPU0_MUX_GTL_TDO")
	)
	(segment
		(start 358.43845 -231.2162)
		(end 358.453436 -231.224836)
		(width 0.0889)
		(layer "B.Cu")
		(net "JTAG_CPU0_MUX_GTL_TDO")
	)
	(segment
		(start 349.51035 -222.263462)
		(end 349.525082 -222.272098)
		(width 0.0889)
		(layer "B.Cu")
		(net "JTAG_CPU0_MUX_GTL_TDO")
	)
	(segment
		(start 346.69095 -222.263462)
		(end 346.705682 -222.272098)
		(width 0.0889)
		(layer "B.Cu")
		(net "JTAG_CPU0_MUX_GTL_TDO")
	)
	(segment
		(start 354.506784 -224.379536)
		(end 354.506784 -224.389442)
		(width 0.0889)
		(layer "B.Cu")
		(net "JTAG_CPU0_MUX_GTL_TDO")
	)
	(segment
		(start 339.17255 -222.263462)
		(end 339.187282 -222.272098)
		(width 0.0889)
		(layer "B.Cu")
		(net "JTAG_CPU0_MUX_GTL_TDO")
	)
	(segment
		(start 217.794078 -195.36791)
		(end 217.324178 -194.89801)
		(width 0.12954)
		(layer "B.Cu")
		(net "JTAG_CPU0_MUX_GTL_TDO")
	)
	(segment
		(start 338.23275 -222.263462)
		(end 338.247482 -222.272098)
		(width 0.0889)
		(layer "B.Cu")
		(net "JTAG_CPU0_MUX_GTL_TDO")
	)
	(segment
		(start 327.613518 -186.89955)
		(end 327.613518 -188.21273)
		(width 0.12954)
		(layer "B.Cu")
		(net "JTAG_CPU0_MUX_GTL_TDO")
	)
	(segment
		(start 356.948232 -229.597204)
		(end 356.962964 -229.588568)
		(width 0.0889)
		(layer "B.Cu")
		(net "JTAG_CPU0_MUX_GTL_TDO")
	)
	(segment
		(start 355.625146 -227.964238)
		(end 355.634036 -227.969318)
		(width 0.0889)
		(layer "B.Cu")
		(net "JTAG_CPU0_MUX_GTL_TDO")
	)
	(segment
		(start 327.082658 -192.98793)
		(end 327.082658 -213.497922)
		(width 0.12954)
		(layer "B.Cu")
		(net "JTAG_CPU0_MUX_GTL_TDO")
	)
	(segment
		(start 334.941926 -221.35719)
		(end 335.520792 -221.35719)
		(width 0.12954)
		(layer "B.Cu")
		(net "JTAG_CPU0_MUX_GTL_TDO")
	)
	(segment
		(start 214.431372 -194.29857)
		(end 214.212678 -194.079876)
		(width 0.12954)
		(layer "B.Cu")
		(net "JTAG_CPU0_MUX_GTL_TDO")
	)
	(segment
		(start 356.094792 -228.778308)
		(end 356.109778 -228.786944)
		(width 0.0889)
		(layer "B.Cu")
		(net "JTAG_CPU0_MUX_GTL_TDO")
	)
	(segment
		(start 327.10374 -183.430672)
		(end 327.10374 -186.389772)
		(width 0.12954)
		(layer "B.Cu")
		(net "JTAG_CPU0_MUX_GTL_TDO")
	)
	(segment
		(start 359.893616 -233.613198)
		(end 360.05008 -233.34218)
		(width 0.0889)
		(layer "B.Cu")
		(net "JTAG_CPU0_MUX_GTL_TDO")
	)
	(segment
		(start 217.166698 -194.29857)
		(end 214.431372 -194.29857)
		(width 0.12954)
		(layer "B.Cu")
		(net "JTAG_CPU0_MUX_GTL_TDO")
	)
	(segment
		(start 351.38995 -222.263462)
		(end 351.404682 -222.272098)
		(width 0.0889)
		(layer "B.Cu")
		(net "JTAG_CPU0_MUX_GTL_TDO")
	)
	(segment
		(start 357.974392 -230.40594)
		(end 357.989378 -230.414576)
		(width 0.0889)
		(layer "B.Cu")
		(net "JTAG_CPU0_MUX_GTL_TDO")
	)
	(segment
		(start 328.405998 -191.66459)
		(end 327.082658 -192.98793)
		(width 0.12954)
		(layer "B.Cu")
		(net "JTAG_CPU0_MUX_GTL_TDO")
	)
	(segment
		(start 344.81135 -222.263462)
		(end 344.826082 -222.272098)
		(width 0.0889)
		(layer "B.Cu")
		(net "JTAG_CPU0_MUX_GTL_TDO")
	)
	(segment
		(start 342.93175 -222.263462)
		(end 342.946482 -222.272098)
		(width 0.0889)
		(layer "B.Cu")
		(net "JTAG_CPU0_MUX_GTL_TDO")
	)
	(segment
		(start 358.923082 -232.038906)
		(end 358.929178 -232.042462)
		(width 0.0889)
		(layer "B.Cu")
		(net "JTAG_CPU0_MUX_GTL_TDO")
	)
	(segment
		(start 355.446584 -226.003104)
		(end 355.446584 -226.017328)
		(width 0.0889)
		(layer "B.Cu")
		(net "JTAG_CPU0_MUX_GTL_TDO")
	)
	(segment
		(start 327.10374 -186.389772)
		(end 327.613518 -186.89955)
		(width 0.12954)
		(layer "B.Cu")
		(net "JTAG_CPU0_MUX_GTL_TDO")
	)
	(segment
		(start 348.57055 -222.263462)
		(end 348.585282 -222.272098)
		(width 0.0889)
		(layer "B.Cu")
		(net "JTAG_CPU0_MUX_GTL_TDO")
	)
	(segment
		(start 352.32975 -222.263462)
		(end 352.344482 -222.272098)
		(width 0.0889)
		(layer "B.Cu")
		(net "JTAG_CPU0_MUX_GTL_TDO")
	)
	(segment
		(start 354.97643 -225.187764)
		(end 354.97643 -225.203258)
		(width 0.0889)
		(layer "B.Cu")
		(net "JTAG_CPU0_MUX_GTL_TDO")
	)
	(segment
		(start 353.745546 -223.080834)
		(end 353.754436 -223.085914)
		(width 0.0889)
		(layer "B.Cu")
		(net "JTAG_CPU0_MUX_GTL_TDO")
	)
	(segment
		(start 359.384346 -232.847642)
		(end 359.393236 -232.852722)
		(width 0.0889)
		(layer "B.Cu")
		(net "JTAG_CPU0_MUX_GTL_TDO")
	)
	(segment
		(start 355.91623 -228.436932)
		(end 355.91623 -228.45903)
		(width 0.0889)
		(layer "B.Cu")
		(net "JTAG_CPU0_MUX_GTL_TDO")
	)
	(segment
		(start 337.120484 -221.937834)
		(end 337.120484 -221.956376)
		(width 0.0889)
		(layer "B.Cu")
		(net "JTAG_CPU0_MUX_GTL_TDO")
	)
	(arc
		(start 354.694236 -224.7138)
		(mid 354.897059 -224.914031)
		(end 354.97643 -225.187764)
		(width 0.0889)
		(layer "B.Cu")
		(net "JTAG_CPU0_MUX_GTL_TDO")
	)
	(arc
		(start 354.97643 -225.203258)
		(mid 355.024109 -225.386158)
		(end 355.154992 -225.522536)
		(width 0.0889)
		(layer "B.Cu")
		(net "JTAG_CPU0_MUX_GTL_TDO")
	)
	(arc
		(start 349.899478 -222.272098)
		(mid 350.173677 -222.196263)
		(end 350.45015 -222.263462)
		(width 0.0889)
		(layer "B.Cu")
		(net "JTAG_CPU0_MUX_GTL_TDO")
	)
	(arc
		(start 355.634036 -227.969318)
		(mid 355.835318 -228.166805)
		(end 355.91623 -228.436932)
		(width 0.0889)
		(layer "B.Cu")
		(net "JTAG_CPU0_MUX_GTL_TDO")
	)
	(arc
		(start 359.67543 -233.34218)
		(mid 359.71229 -233.503977)
		(end 359.815384 -233.634026)
		(width 0.0889)
		(layer "B.Cu")
		(net "JTAG_CPU0_MUX_GTL_TDO")
	)
	(arc
		(start 350.464882 -222.272098)
		(mid 350.65208 -222.322241)
		(end 350.839278 -222.272098)
		(width 0.0889)
		(layer "B.Cu")
		(net "JTAG_CPU0_MUX_GTL_TDO")
	)
	(arc
		(start 349.525082 -222.272098)
		(mid 349.71228 -222.322241)
		(end 349.899478 -222.272098)
		(width 0.0889)
		(layer "B.Cu")
		(net "JTAG_CPU0_MUX_GTL_TDO")
	)
	(arc
		(start 344.260678 -222.272098)
		(mid 344.534877 -222.196263)
		(end 344.81135 -222.263462)
		(width 0.0889)
		(layer "B.Cu")
		(net "JTAG_CPU0_MUX_GTL_TDO")
	)
	(arc
		(start 342.381078 -222.272098)
		(mid 342.655277 -222.196263)
		(end 342.93175 -222.263462)
		(width 0.0889)
		(layer "B.Cu")
		(net "JTAG_CPU0_MUX_GTL_TDO")
	)
	(arc
		(start 345.765882 -222.272098)
		(mid 345.95308 -222.322241)
		(end 346.140278 -222.272098)
		(width 0.0889)
		(layer "B.Cu")
		(net "JTAG_CPU0_MUX_GTL_TDO")
	)
	(arc
		(start 350.839278 -222.272098)
		(mid 351.113477 -222.196263)
		(end 351.38995 -222.263462)
		(width 0.0889)
		(layer "B.Cu")
		(net "JTAG_CPU0_MUX_GTL_TDO")
	)
	(arc
		(start 351.779078 -222.272098)
		(mid 352.053277 -222.196263)
		(end 352.32975 -222.263462)
		(width 0.0889)
		(layer "B.Cu")
		(net "JTAG_CPU0_MUX_GTL_TDO")
	)
	(arc
		(start 339.187282 -222.272098)
		(mid 339.37448 -222.322241)
		(end 339.561678 -222.272098)
		(width 0.0889)
		(layer "B.Cu")
		(net "JTAG_CPU0_MUX_GTL_TDO")
	)
	(arc
		(start 359.205784 -232.528364)
		(mid 359.253463 -232.711264)
		(end 359.384346 -232.847642)
		(width 0.0889)
		(layer "B.Cu")
		(net "JTAG_CPU0_MUX_GTL_TDO")
	)
	(arc
		(start 355.625146 -227.325682)
		(mid 355.446549 -227.64496)
		(end 355.625146 -227.964238)
		(width 0.0889)
		(layer "B.Cu")
		(net "JTAG_CPU0_MUX_GTL_TDO")
	)
	(arc
		(start 354.036884 -223.575626)
		(mid 354.084563 -223.758526)
		(end 354.215446 -223.894904)
		(width 0.0889)
		(layer "B.Cu")
		(net "JTAG_CPU0_MUX_GTL_TDO")
	)
	(arc
		(start 352.344482 -222.272098)
		(mid 352.53168 -222.322241)
		(end 352.718878 -222.272098)
		(width 0.0889)
		(layer "B.Cu")
		(net "JTAG_CPU0_MUX_GTL_TDO")
	)
	(arc
		(start 336.272632 -221.458282)
		(mid 336.833608 -221.455751)
		(end 337.120484 -221.937834)
		(width 0.0889)
		(layer "B.Cu")
		(net "JTAG_CPU0_MUX_GTL_TDO")
	)
	(arc
		(start 344.826082 -222.272098)
		(mid 345.01328 -222.322241)
		(end 345.200478 -222.272098)
		(width 0.0889)
		(layer "B.Cu")
		(net "JTAG_CPU0_MUX_GTL_TDO")
	)
	(arc
		(start 343.886282 -222.272098)
		(mid 344.07348 -222.322241)
		(end 344.260678 -222.272098)
		(width 0.0889)
		(layer "B.Cu")
		(net "JTAG_CPU0_MUX_GTL_TDO")
	)
	(arc
		(start 347.645482 -222.272098)
		(mid 347.83268 -222.322241)
		(end 348.019878 -222.272098)
		(width 0.0889)
		(layer "B.Cu")
		(net "JTAG_CPU0_MUX_GTL_TDO")
	)
	(arc
		(start 358.26573 -230.900478)
		(mid 358.311734 -231.080415)
		(end 358.43845 -231.2162)
		(width 0.0889)
		(layer "B.Cu")
		(net "JTAG_CPU0_MUX_GTL_TDO")
	)
	(arc
		(start 343.320878 -222.272098)
		(mid 343.595077 -222.196263)
		(end 343.87155 -222.263462)
		(width 0.0889)
		(layer "B.Cu")
		(net "JTAG_CPU0_MUX_GTL_TDO")
	)
	(arc
		(start 335.898236 -221.458282)
		(mid 336.085434 -221.508425)
		(end 336.272632 -221.458282)
		(width 0.0889)
		(layer "B.Cu")
		(net "JTAG_CPU0_MUX_GTL_TDO")
	)
	(arc
		(start 337.120484 -221.956376)
		(mid 337.311358 -222.274185)
		(end 337.682078 -222.272098)
		(width 0.0889)
		(layer "B.Cu")
		(net "JTAG_CPU0_MUX_GTL_TDO")
	)
	(arc
		(start 356.962964 -229.588568)
		(mid 357.514157 -229.597366)
		(end 357.79583 -230.071168)
		(width 0.0889)
		(layer "B.Cu")
		(net "JTAG_CPU0_MUX_GTL_TDO")
	)
	(arc
		(start 358.453436 -231.224836)
		(mid 358.655722 -231.423817)
		(end 358.735884 -231.696006)
		(width 0.0889)
		(layer "B.Cu")
		(net "JTAG_CPU0_MUX_GTL_TDO")
	)
	(arc
		(start 345.200478 -222.272098)
		(mid 345.474677 -222.196263)
		(end 345.75115 -222.263462)
		(width 0.0889)
		(layer "B.Cu")
		(net "JTAG_CPU0_MUX_GTL_TDO")
	)
	(arc
		(start 339.561678 -222.272098)
		(mid 339.835877 -222.196263)
		(end 340.11235 -222.263462)
		(width 0.0889)
		(layer "B.Cu")
		(net "JTAG_CPU0_MUX_GTL_TDO")
	)
	(arc
		(start 338.621878 -222.272098)
		(mid 338.896077 -222.196263)
		(end 339.17255 -222.263462)
		(width 0.0889)
		(layer "B.Cu")
		(net "JTAG_CPU0_MUX_GTL_TDO")
	)
	(arc
		(start 356.386384 -229.272846)
		(mid 356.573683 -229.597287)
		(end 356.948232 -229.597204)
		(width 0.0889)
		(layer "B.Cu")
		(net "JTAG_CPU0_MUX_GTL_TDO")
	)
	(arc
		(start 347.080078 -222.272098)
		(mid 347.354277 -222.196263)
		(end 347.63075 -222.263462)
		(width 0.0889)
		(layer "B.Cu")
		(net "JTAG_CPU0_MUX_GTL_TDO")
	)
	(arc
		(start 341.441278 -222.272098)
		(mid 341.715477 -222.196263)
		(end 341.99195 -222.263462)
		(width 0.0889)
		(layer "B.Cu")
		(net "JTAG_CPU0_MUX_GTL_TDO")
	)
	(arc
		(start 346.140278 -222.272098)
		(mid 346.414477 -222.196263)
		(end 346.69095 -222.263462)
		(width 0.0889)
		(layer "B.Cu")
		(net "JTAG_CPU0_MUX_GTL_TDO")
	)
	(arc
		(start 358.735884 -231.723184)
		(mid 358.788154 -231.905549)
		(end 358.923082 -232.038906)
		(width 0.0889)
		(layer "B.Cu")
		(net "JTAG_CPU0_MUX_GTL_TDO")
	)
	(arc
		(start 351.404682 -222.272098)
		(mid 351.59188 -222.322241)
		(end 351.779078 -222.272098)
		(width 0.0889)
		(layer "B.Cu")
		(net "JTAG_CPU0_MUX_GTL_TDO")
	)
	(arc
		(start 337.682078 -222.272098)
		(mid 337.956277 -222.196263)
		(end 338.23275 -222.263462)
		(width 0.0889)
		(layer "B.Cu")
		(net "JTAG_CPU0_MUX_GTL_TDO")
	)
	(arc
		(start 355.640132 -226.345242)
		(mid 355.916458 -226.831144)
		(end 355.640132 -227.317046)
		(width 0.0889)
		(layer "B.Cu")
		(net "JTAG_CPU0_MUX_GTL_TDO")
	)
	(arc
		(start 348.019878 -222.272098)
		(mid 348.294077 -222.196263)
		(end 348.57055 -222.263462)
		(width 0.0889)
		(layer "B.Cu")
		(net "JTAG_CPU0_MUX_GTL_TDO")
	)
	(arc
		(start 352.718878 -222.272098)
		(mid 353.284377 -222.271859)
		(end 353.566984 -222.761556)
		(width 0.0889)
		(layer "B.Cu")
		(net "JTAG_CPU0_MUX_GTL_TDO")
	)
	(arc
		(start 357.79583 -230.086662)
		(mid 357.843509 -230.269562)
		(end 357.974392 -230.40594)
		(width 0.0889)
		(layer "B.Cu")
		(net "JTAG_CPU0_MUX_GTL_TDO")
	)
	(arc
		(start 354.506784 -224.389442)
		(mid 354.554463 -224.572342)
		(end 354.685346 -224.70872)
		(width 0.0889)
		(layer "B.Cu")
		(net "JTAG_CPU0_MUX_GTL_TDO")
	)
	(arc
		(start 353.566984 -222.761556)
		(mid 353.614663 -222.944456)
		(end 353.745546 -223.080834)
		(width 0.0889)
		(layer "B.Cu")
		(net "JTAG_CPU0_MUX_GTL_TDO")
	)
	(arc
		(start 355.91623 -228.45903)
		(mid 355.963909 -228.64193)
		(end 356.094792 -228.778308)
		(width 0.0889)
		(layer "B.Cu")
		(net "JTAG_CPU0_MUX_GTL_TDO")
	)
	(arc
		(start 346.705682 -222.272098)
		(mid 346.89288 -222.322241)
		(end 347.080078 -222.272098)
		(width 0.0889)
		(layer "B.Cu")
		(net "JTAG_CPU0_MUX_GTL_TDO")
	)
	(arc
		(start 342.946482 -222.272098)
		(mid 343.13368 -222.322241)
		(end 343.320878 -222.272098)
		(width 0.0889)
		(layer "B.Cu")
		(net "JTAG_CPU0_MUX_GTL_TDO")
	)
	(arc
		(start 355.163882 -225.527616)
		(mid 355.367363 -225.72842)
		(end 355.446584 -226.003104)
		(width 0.0889)
		(layer "B.Cu")
		(net "JTAG_CPU0_MUX_GTL_TDO")
	)
	(arc
		(start 338.247482 -222.272098)
		(mid 338.43468 -222.322241)
		(end 338.621878 -222.272098)
		(width 0.0889)
		(layer "B.Cu")
		(net "JTAG_CPU0_MUX_GTL_TDO")
	)
	(arc
		(start 335.520792 -221.35719)
		(mid 335.716161 -221.382909)
		(end 335.898236 -221.458282)
		(width 0.0889)
		(layer "B.Cu")
		(net "JTAG_CPU0_MUX_GTL_TDO")
	)
	(arc
		(start 354.224336 -223.899984)
		(mid 354.428671 -224.102589)
		(end 354.506784 -224.379536)
		(width 0.0889)
		(layer "B.Cu")
		(net "JTAG_CPU0_MUX_GTL_TDO")
	)
	(arc
		(start 342.006682 -222.272098)
		(mid 342.19388 -222.322241)
		(end 342.381078 -222.272098)
		(width 0.0889)
		(layer "B.Cu")
		(net "JTAG_CPU0_MUX_GTL_TDO")
	)
	(arc
		(start 341.066882 -222.272098)
		(mid 341.25408 -222.322241)
		(end 341.441278 -222.272098)
		(width 0.0889)
		(layer "B.Cu")
		(net "JTAG_CPU0_MUX_GTL_TDO")
	)
	(arc
		(start 356.109778 -228.786944)
		(mid 356.312365 -228.993295)
		(end 356.386384 -229.272846)
		(width 0.0889)
		(layer "B.Cu")
		(net "JTAG_CPU0_MUX_GTL_TDO")
	)
	(arc
		(start 348.585282 -222.272098)
		(mid 348.77248 -222.322241)
		(end 348.959678 -222.272098)
		(width 0.0889)
		(layer "B.Cu")
		(net "JTAG_CPU0_MUX_GTL_TDO")
	)
	(arc
		(start 348.959678 -222.272098)
		(mid 349.233877 -222.196263)
		(end 349.51035 -222.263462)
		(width 0.0889)
		(layer "B.Cu")
		(net "JTAG_CPU0_MUX_GTL_TDO")
	)
	(arc
		(start 353.754436 -223.085914)
		(mid 353.957741 -223.28678)
		(end 354.036884 -223.561402)
		(width 0.0889)
		(layer "B.Cu")
		(net "JTAG_CPU0_MUX_GTL_TDO")
	)
	(arc
		(start 340.501478 -222.272098)
		(mid 340.775677 -222.196263)
		(end 341.05215 -222.263462)
		(width 0.0889)
		(layer "B.Cu")
		(net "JTAG_CPU0_MUX_GTL_TDO")
	)
	(arc
		(start 340.127082 -222.272098)
		(mid 340.31428 -222.322241)
		(end 340.501478 -222.272098)
		(width 0.0889)
		(layer "B.Cu")
		(net "JTAG_CPU0_MUX_GTL_TDO")
	)
	(arc
		(start 357.989378 -230.414576)
		(mid 358.191791 -230.620989)
		(end 358.26573 -230.900478)
		(width 0.0889)
		(layer "B.Cu")
		(net "JTAG_CPU0_MUX_GTL_TDO")
	)
	(arc
		(start 359.393236 -232.852722)
		(mid 359.596059 -233.052953)
		(end 359.67543 -233.326686)
		(width 0.0889)
		(layer "B.Cu")
		(net "JTAG_CPU0_MUX_GTL_TDO")
	)
	(arc
		(start 355.446584 -226.017328)
		(mid 355.494263 -226.200228)
		(end 355.625146 -226.336606)
		(width 0.0889)
		(layer "B.Cu")
		(net "JTAG_CPU0_MUX_GTL_TDO")
	)
	(arc
		(start 358.929178 -232.042462)
		(mid 359.131765 -232.248813)
		(end 359.205784 -232.528364)
		(width 0.0889)
		(layer "B.Cu")
		(net "JTAG_CPU0_MUX_GTL_TDO")
	)
	(segment
		(start 225.806 -187.340748)
		(end 225.806 -188.018928)
		(width 0.127)
		(layer "In13.Cu")
		(net "JTAG_CPU0_MUX_GTL_TDO")
	)
	(segment
		(start 225.806 -188.018928)
		(end 225.9965 -188.209428)
		(width 0.127)
		(layer "In13.Cu")
		(net "JTAG_CPU0_MUX_GTL_TDO")
	)
	(segment
		(start 220.872304 -195.377308)
		(end 214.36584 -195.377308)
		(width 0.127)
		(layer "In13.Cu")
		(net "JTAG_CPU0_MUX_GTL_TDO")
	)
	(segment
		(start 225.9965 -188.209428)
		(end 225.9965 -190.253112)
		(width 0.127)
		(layer "In13.Cu")
		(net "JTAG_CPU0_MUX_GTL_TDO")
	)
	(segment
		(start 213.824058 -194.835526)
		(end 213.824058 -194.76593)
		(width 0.127)
		(layer "In13.Cu")
		(net "JTAG_CPU0_MUX_GTL_TDO")
	)
	(segment
		(start 225.9965 -190.253112)
		(end 220.872304 -195.377308)
		(width 0.127)
		(layer "In13.Cu")
		(net "JTAG_CPU0_MUX_GTL_TDO")
	)
	(segment
		(start 214.36584 -195.377308)
		(end 213.824058 -194.835526)
		(width 0.127)
		(layer "In13.Cu")
		(net "JTAG_CPU0_MUX_GTL_TDO")
	)
	(segment
		(start 144.16405 -25.110948)
		(end 144.23771 -25.037288)
		(width 0.12954)
		(layer "F.Cu")
		(net "JTAG_BMC_TMS")
	)
	(segment
		(start 147.828 -19.944334)
		(end 147.828 -15.260828)
		(width 0.12954)
		(layer "F.Cu")
		(net "JTAG_BMC_TMS")
	)
	(segment
		(start 152.483566 -9.743948)
		(end 154.305254 -9.743948)
		(width 0.12954)
		(layer "F.Cu")
		(net "JTAG_BMC_TMS")
	)
	(segment
		(start 149.479 -13.323824)
		(end 149.479 -12.446508)
		(width 0.12954)
		(layer "F.Cu")
		(net "JTAG_BMC_TMS")
	)
	(segment
		(start 155.057094 -10.495788)
		(end 155.057094 -13.600176)
		(width 0.12954)
		(layer "F.Cu")
		(net "JTAG_BMC_TMS")
	)
	(segment
		(start 149.689566 -11.38809)
		(end 149.833838 -11.039856)
		(width 0.12954)
		(layer "F.Cu")
		(net "JTAG_BMC_TMS")
	)
	(segment
		(start 149.136608 -14.15034)
		(end 149.479 -13.323824)
		(width 0.12954)
		(layer "F.Cu")
		(net "JTAG_BMC_TMS")
	)
	(segment
		(start 144.23771 -25.037288)
		(end 144.23771 -23.534624)
		(width 0.12954)
		(layer "F.Cu")
		(net "JTAG_BMC_TMS")
	)
	(segment
		(start 154.305254 -9.743948)
		(end 155.057094 -10.495788)
		(width 0.12954)
		(layer "F.Cu")
		(net "JTAG_BMC_TMS")
	)
	(segment
		(start 147.828 -15.260828)
		(end 148.536152 -14.552676)
		(width 0.12954)
		(layer "F.Cu")
		(net "JTAG_BMC_TMS")
	)
	(segment
		(start 148.536152 -14.552676)
		(end 148.87448 -14.412468)
		(width 0.12954)
		(layer "F.Cu")
		(net "JTAG_BMC_TMS")
	)
	(segment
		(start 144.23771 -23.534624)
		(end 147.828 -19.944334)
		(width 0.12954)
		(layer "F.Cu")
		(net "JTAG_BMC_TMS")
	)
	(segment
		(start 149.479 -12.446508)
		(end 149.689566 -11.38809)
		(width 0.12954)
		(layer "F.Cu")
		(net "JTAG_BMC_TMS")
	)
	(segment
		(start 149.833838 -11.039856)
		(end 150.17242 -10.701274)
		(width 0.12954)
		(layer "F.Cu")
		(net "JTAG_BMC_TMS")
	)
	(segment
		(start 148.87448 -14.412468)
		(end 149.136608 -14.15034)
		(width 0.12954)
		(layer "F.Cu")
		(net "JTAG_BMC_TMS")
	)
	(segment
		(start 150.17242 -10.701274)
		(end 152.483566 -9.743948)
		(width 0.12954)
		(layer "F.Cu")
		(net "JTAG_BMC_TMS")
	)
	(via
		(at 144.23771 -23.534624)
		(size 0.508)
		(drill 0.254)
		(layers "F.Cu" "B.Cu")
		(net "JTAG_BMC_TMS")
	)
	(segment
		(start 154.14752 -11.349228)
		(end 153.856944 -11.639804)
		(width 0.12954)
		(layer "F.Cu")
		(net "JTAG_BMC_TDO")
	)
	(segment
		(start 129.55905 -56.733948)
		(end 130.175 -56.733948)
		(width 0.12954)
		(layer "F.Cu")
		(net "JTAG_BMC_TDO")
	)
	(segment
		(start 153.856944 -11.639804)
		(end 153.856944 -13.600176)
		(width 0.12954)
		(layer "F.Cu")
		(net "JTAG_BMC_TDO")
	)
	(via
		(at 154.14752 -11.349228)
		(size 0.508)
		(drill 0.254)
		(layers "F.Cu" "B.Cu")
		(net "JTAG_BMC_TDO")
	)
	(via
		(at 130.175 -56.733948)
		(size 0.508)
		(drill 0.254)
		(layers "F.Cu" "B.Cu")
		(net "JTAG_BMC_TDO")
	)
	(via
		(at 143.4084 -51.476148)
		(size 0.508)
		(drill 0.254)
		(layers "F.Cu" "B.Cu")
		(net "JTAG_BMC_TDO")
	)
	(segment
		(start 152.68956 -10.450068)
		(end 150.602442 -10.450068)
		(width 0.127)
		(layer "In2.Cu")
		(net "JTAG_BMC_TDO")
	)
	(segment
		(start 148.55698 -14.65072)
		(end 148.13788 -14.65072)
		(width 0.127)
		(layer "In2.Cu")
		(net "JTAG_BMC_TDO")
	)
	(segment
		(start 154.14752 -11.349228)
		(end 153.58872 -11.349228)
		(width 0.127)
		(layer "In2.Cu")
		(net "JTAG_BMC_TDO")
	)
	(segment
		(start 149.68474 -13.52296)
		(end 148.55698 -14.65072)
		(width 0.127)
		(layer "In2.Cu")
		(net "JTAG_BMC_TDO")
	)
	(segment
		(start 153.58872 -11.349228)
		(end 152.68956 -10.450068)
		(width 0.127)
		(layer "In2.Cu")
		(net "JTAG_BMC_TDO")
	)
	(segment
		(start 148.13788 -14.65072)
		(end 145.94078 -16.84782)
		(width 0.127)
		(layer "In2.Cu")
		(net "JTAG_BMC_TDO")
	)
	(segment
		(start 144.2339 -38.164008)
		(end 143.4084 -38.989508)
		(width 0.127)
		(layer "In2.Cu")
		(net "JTAG_BMC_TDO")
	)
	(segment
		(start 143.4084 -38.989508)
		(end 143.4084 -51.476148)
		(width 0.127)
		(layer "In2.Cu")
		(net "JTAG_BMC_TDO")
	)
	(segment
		(start 145.94078 -33.371028)
		(end 144.2339 -35.077908)
		(width 0.127)
		(layer "In2.Cu")
		(net "JTAG_BMC_TDO")
	)
	(segment
		(start 149.68474 -11.36777)
		(end 149.68474 -13.52296)
		(width 0.127)
		(layer "In2.Cu")
		(net "JTAG_BMC_TDO")
	)
	(segment
		(start 144.2339 -35.077908)
		(end 144.2339 -38.164008)
		(width 0.127)
		(layer "In2.Cu")
		(net "JTAG_BMC_TDO")
	)
	(segment
		(start 150.602442 -10.450068)
		(end 149.68474 -11.36777)
		(width 0.127)
		(layer "In2.Cu")
		(net "JTAG_BMC_TDO")
	)
	(segment
		(start 145.94078 -16.84782)
		(end 145.94078 -33.371028)
		(width 0.127)
		(layer "In2.Cu")
		(net "JTAG_BMC_TDO")
	)
	(segment
		(start 143.4084 -54.371748)
		(end 143.4084 -51.476148)
		(width 0.127)
		(layer "In6.Cu")
		(net "JTAG_BMC_TDO")
	)
	(segment
		(start 130.175 -56.733948)
		(end 141.0462 -56.733948)
		(width 0.127)
		(layer "In6.Cu")
		(net "JTAG_BMC_TDO")
	)
	(segment
		(start 141.0462 -56.733948)
		(end 143.4084 -54.371748)
		(width 0.127)
		(layer "In6.Cu")
		(net "JTAG_BMC_TDO")
	)
	(segment
		(start 148.656548 -14.973554)
		(end 148.968714 -14.844268)
		(width 0.12954)
		(layer "F.Cu")
		(net "JTAG_BMC_TDI")
	)
	(segment
		(start 144.16405 -26.126948)
		(end 144.8181 -26.126948)
		(width 0.12954)
		(layer "F.Cu")
		(net "JTAG_BMC_TDI")
	)
	(segment
		(start 149.83714 -12.489434)
		(end 150.020274 -11.56843)
		(width 0.12954)
		(layer "F.Cu")
		(net "JTAG_BMC_TDI")
	)
	(segment
		(start 146.407378 -24.53767)
		(end 148.18614 -20.243292)
		(width 0.12954)
		(layer "F.Cu")
		(net "JTAG_BMC_TDI")
	)
	(segment
		(start 154.456892 -13.041376)
		(end 154.456892 -13.600176)
		(width 0.12954)
		(layer "F.Cu")
		(net "JTAG_BMC_TDI")
	)
	(segment
		(start 148.18614 -15.443962)
		(end 148.656548 -14.973554)
		(width 0.12954)
		(layer "F.Cu")
		(net "JTAG_BMC_TDI")
	)
	(segment
		(start 150.166578 -11.21537)
		(end 150.299928 -11.08202)
		(width 0.12954)
		(layer "F.Cu")
		(net "JTAG_BMC_TDI")
	)
	(segment
		(start 148.968714 -14.844268)
		(end 149.507956 -14.305026)
		(width 0.12954)
		(layer "F.Cu")
		(net "JTAG_BMC_TDI")
	)
	(segment
		(start 149.83714 -13.51026)
		(end 149.83714 -12.489434)
		(width 0.12954)
		(layer "F.Cu")
		(net "JTAG_BMC_TDI")
	)
	(segment
		(start 153.924 -10.124948)
		(end 154.63012 -10.831068)
		(width 0.12954)
		(layer "F.Cu")
		(net "JTAG_BMC_TDI")
	)
	(segment
		(start 154.63012 -10.831068)
		(end 154.63012 -12.868148)
		(width 0.12954)
		(layer "F.Cu")
		(net "JTAG_BMC_TDI")
	)
	(segment
		(start 154.63012 -12.868148)
		(end 154.456892 -13.041376)
		(width 0.12954)
		(layer "F.Cu")
		(net "JTAG_BMC_TDI")
	)
	(segment
		(start 149.507956 -14.305026)
		(end 149.83714 -13.51026)
		(width 0.12954)
		(layer "F.Cu")
		(net "JTAG_BMC_TDI")
	)
	(segment
		(start 144.8181 -26.126948)
		(end 146.407378 -24.53767)
		(width 0.12954)
		(layer "F.Cu")
		(net "JTAG_BMC_TDI")
	)
	(segment
		(start 150.020274 -11.56843)
		(end 150.166578 -11.21537)
		(width 0.12954)
		(layer "F.Cu")
		(net "JTAG_BMC_TDI")
	)
	(segment
		(start 148.18614 -20.243292)
		(end 148.18614 -15.443962)
		(width 0.12954)
		(layer "F.Cu")
		(net "JTAG_BMC_TDI")
	)
	(segment
		(start 150.299928 -11.08202)
		(end 152.610566 -10.124948)
		(width 0.12954)
		(layer "F.Cu")
		(net "JTAG_BMC_TDI")
	)
	(segment
		(start 152.610566 -10.124948)
		(end 153.924 -10.124948)
		(width 0.12954)
		(layer "F.Cu")
		(net "JTAG_BMC_TDI")
	)
	(via
		(at 144.8181 -26.126948)
		(size 0.508)
		(drill 0.254)
		(layers "F.Cu" "B.Cu")
		(net "JTAG_BMC_TDI")
	)
	(segment
		(start 155.5242 -11.113516)
		(end 155.656788 -10.980928)
		(width 0.12954)
		(layer "F.Cu")
		(net "JTAG_BMC_TCK")
	)
	(segment
		(start 155.5242 -13.467334)
		(end 155.5242 -11.113516)
		(width 0.12954)
		(layer "F.Cu")
		(net "JTAG_BMC_TCK")
	)
	(segment
		(start 155.657042 -13.600176)
		(end 155.5242 -13.467334)
		(width 0.12954)
		(layer "F.Cu")
		(net "JTAG_BMC_TCK")
	)
	(via
		(at 155.656788 -10.980928)
		(size 0.508)
		(drill 0.254)
		(layers "F.Cu" "B.Cu")
		(net "JTAG_BMC_TCK")
	)
	(via
		(at 154.33802 -10.074148)
		(size 0.7112)
		(drill 0.3556)
		(layers "F.Cu" "B.Cu")
		(net "JTAG_BMC_TCK")
	)
	(segment
		(start 154.33802 -10.074148)
		(end 154.750008 -10.074148)
		(width 0.12954)
		(layer "B.Cu")
		(net "JTAG_BMC_TCK")
	)
	(segment
		(start 149.8854 -11.267948)
		(end 151.0792 -10.074148)
		(width 0.12954)
		(layer "B.Cu")
		(net "JTAG_BMC_TCK")
	)
	(segment
		(start 151.0792 -10.074148)
		(end 154.33802 -10.074148)
		(width 0.12954)
		(layer "B.Cu")
		(net "JTAG_BMC_TCK")
	)
	(segment
		(start 149.8854 -14.423898)
		(end 149.8854 -11.267948)
		(width 0.12954)
		(layer "B.Cu")
		(net "JTAG_BMC_TCK")
	)
	(segment
		(start 154.750008 -10.074148)
		(end 155.656788 -10.980928)
		(width 0.12954)
		(layer "B.Cu")
		(net "JTAG_BMC_TCK")
	)
	(segment
		(start 118.969536 -67.07759)
		(end 118.954042 -67.093084)
		(width 0.12954)
		(layer "F.Cu")
		(net "JTAG_BMC_PLD_TMS")
	)
	(segment
		(start 119.00408 -67.143122)
		(end 118.954042 -67.093084)
		(width 0.12954)
		(layer "F.Cu")
		(net "JTAG_BMC_PLD_TMS")
	)
	(segment
		(start 120.714008 -67.07759)
		(end 118.969536 -67.07759)
		(width 0.12954)
		(layer "F.Cu")
		(net "JTAG_BMC_PLD_TMS")
	)
	(segment
		(start 120.317006 -76.99883)
		(end 119.546116 -76.99883)
		(width 0.12954)
		(layer "F.Cu")
		(net "JTAG_BMC_PLD_TMS")
	)
	(segment
		(start 120.6881 -76.627736)
		(end 120.582944 -76.732892)
		(width 0.12954)
		(layer "F.Cu")
		(net "JTAG_BMC_PLD_TMS")
	)
	(segment
		(start 119.377968 -70.751954)
		(end 119.377968 -74.204576)
		(width 0.12954)
		(layer "F.Cu")
		(net "JTAG_BMC_PLD_TMS")
	)
	(segment
		(start 119.38 -70.749922)
		(end 119.377968 -70.751954)
		(width 0.12954)
		(layer "F.Cu")
		(net "JTAG_BMC_PLD_TMS")
	)
	(segment
		(start 119.38 -70.749922)
		(end 119.00408 -70.374002)
		(width 0.12954)
		(layer "F.Cu")
		(net "JTAG_BMC_PLD_TMS")
	)
	(segment
		(start 119.00408 -70.374002)
		(end 119.00408 -67.143122)
		(width 0.12954)
		(layer "F.Cu")
		(net "JTAG_BMC_PLD_TMS")
	)
	(segment
		(start 119.377968 -74.204576)
		(end 120.6881 -75.514708)
		(width 0.12954)
		(layer "F.Cu")
		(net "JTAG_BMC_PLD_TMS")
	)
	(segment
		(start 120.582944 -76.732892)
		(end 120.317006 -76.99883)
		(width 0.12954)
		(layer "F.Cu")
		(net "JTAG_BMC_PLD_TMS")
	)
	(segment
		(start 120.6881 -75.514708)
		(end 120.6881 -76.627736)
		(width 0.12954)
		(layer "F.Cu")
		(net "JTAG_BMC_PLD_TMS")
	)
	(via
		(at 120.582944 -76.732892)
		(size 0.508)
		(drill 0.254)
		(layers "F.Cu" "B.Cu")
		(net "JTAG_BMC_PLD_TMS")
	)
	(segment
		(start 130.994912 -67.338956)
		(end 129.411984 -67.338956)
		(width 0.12954)
		(layer "F.Cu")
		(net "JTAG_BMC_PLD_TDO")
	)
	(segment
		(start 128.029716 -77.821028)
		(end 129.242566 -77.821028)
		(width 0.12954)
		(layer "F.Cu")
		(net "JTAG_BMC_PLD_TDO")
	)
	(segment
		(start 131.014216 -67.319652)
		(end 130.994912 -67.338956)
		(width 0.12954)
		(layer "F.Cu")
		(net "JTAG_BMC_PLD_TDO")
	)
	(segment
		(start 129.411984 -70.623938)
		(end 129.537968 -70.749922)
		(width 0.12954)
		(layer "F.Cu")
		(net "JTAG_BMC_PLD_TDO")
	)
	(segment
		(start 129.537968 -70.749922)
		(end 129.537968 -70.751954)
		(width 0.12954)
		(layer "F.Cu")
		(net "JTAG_BMC_PLD_TDO")
	)
	(segment
		(start 129.74955 -70.963536)
		(end 129.537968 -70.751954)
		(width 0.12954)
		(layer "F.Cu")
		(net "JTAG_BMC_PLD_TDO")
	)
	(segment
		(start 129.411984 -67.338956)
		(end 129.411984 -70.623938)
		(width 0.12954)
		(layer "F.Cu")
		(net "JTAG_BMC_PLD_TDO")
	)
	(segment
		(start 129.74955 -77.314044)
		(end 129.74955 -70.963536)
		(width 0.12954)
		(layer "F.Cu")
		(net "JTAG_BMC_PLD_TDO")
	)
	(segment
		(start 129.537968 -70.751954)
		(end 129.54 -70.749922)
		(width 0.12954)
		(layer "F.Cu")
		(net "JTAG_BMC_PLD_TDO")
	)
	(segment
		(start 129.242566 -77.821028)
		(end 129.74955 -77.314044)
		(width 0.12954)
		(layer "F.Cu")
		(net "JTAG_BMC_PLD_TDO")
	)
	(segment
		(start 126.759462 -67.267328)
		(end 126.770384 -67.256406)
		(width 0.12954)
		(layer "F.Cu")
		(net "JTAG_BMC_PLD_TDI")
	)
	(segment
		(start 126.997968 -70.751954)
		(end 127 -70.749922)
		(width 0.12954)
		(layer "F.Cu")
		(net "JTAG_BMC_PLD_TDI")
	)
	(segment
		(start 128.048766 -74.333354)
		(end 126.997968 -73.282556)
		(width 0.12954)
		(layer "F.Cu")
		(net "JTAG_BMC_PLD_TDI")
	)
	(segment
		(start 128.048766 -76.096876)
		(end 128.048766 -74.333354)
		(width 0.12954)
		(layer "F.Cu")
		(net "JTAG_BMC_PLD_TDI")
	)
	(segment
		(start 128.029716 -76.82103)
		(end 128.294384 -76.82103)
		(width 0.12954)
		(layer "F.Cu")
		(net "JTAG_BMC_PLD_TDI")
	)
	(segment
		(start 126.997968 -70.749922)
		(end 126.770384 -70.522338)
		(width 0.12954)
		(layer "F.Cu")
		(net "JTAG_BMC_PLD_TDI")
	)
	(segment
		(start 128.294384 -76.82103)
		(end 128.423924 -76.69149)
		(width 0.12954)
		(layer "F.Cu")
		(net "JTAG_BMC_PLD_TDI")
	)
	(segment
		(start 128.423924 -76.472034)
		(end 128.048766 -76.096876)
		(width 0.12954)
		(layer "F.Cu")
		(net "JTAG_BMC_PLD_TDI")
	)
	(segment
		(start 126.770384 -70.522338)
		(end 126.770384 -67.256406)
		(width 0.12954)
		(layer "F.Cu")
		(net "JTAG_BMC_PLD_TDI")
	)
	(segment
		(start 128.423924 -76.69149)
		(end 128.423924 -76.472034)
		(width 0.12954)
		(layer "F.Cu")
		(net "JTAG_BMC_PLD_TDI")
	)
	(segment
		(start 125.205744 -67.267328)
		(end 126.759462 -67.267328)
		(width 0.12954)
		(layer "F.Cu")
		(net "JTAG_BMC_PLD_TDI")
	)
	(segment
		(start 126.997968 -70.751954)
		(end 126.997968 -70.749922)
		(width 0.12954)
		(layer "F.Cu")
		(net "JTAG_BMC_PLD_TDI")
	)
	(segment
		(start 126.997968 -73.282556)
		(end 126.997968 -70.751954)
		(width 0.12954)
		(layer "F.Cu")
		(net "JTAG_BMC_PLD_TDI")
	)
	(segment
		(start 116.399056 -67.064128)
		(end 114.834162 -67.064128)
		(width 0.12954)
		(layer "F.Cu")
		(net "JTAG_BMC_PLD_TCK")
	)
	(segment
		(start 114.834162 -67.064128)
		(end 114.826034 -67.072256)
		(width 0.12954)
		(layer "F.Cu")
		(net "JTAG_BMC_PLD_TCK")
	)
	(segment
		(start 121.46788 -77.998828)
		(end 119.546116 -77.998828)
		(width 0.12954)
		(layer "F.Cu")
		(net "JTAG_BMC_PLD_TCK")
	)
	(segment
		(start 114.826034 -67.072256)
		(end 114.826034 -70.223888)
		(width 0.12954)
		(layer "F.Cu")
		(net "JTAG_BMC_PLD_TCK")
	)
	(segment
		(start 121.852944 -78.383892)
		(end 121.46788 -77.998828)
		(width 0.12954)
		(layer "F.Cu")
		(net "JTAG_BMC_PLD_TCK")
	)
	(segment
		(start 114.826034 -70.223888)
		(end 114.3 -70.749922)
		(width 0.12954)
		(layer "F.Cu")
		(net "JTAG_BMC_PLD_TCK")
	)
	(via
		(at 121.852944 -78.383892)
		(size 0.508)
		(drill 0.254)
		(layers "F.Cu" "B.Cu")
		(net "JTAG_BMC_PLD_TCK")
	)
	(segment
		(start 117.811804 -72.614028)
		(end 114.92738 -72.614028)
		(width 0.12954)
		(layer "B.Cu")
		(net "JTAG_BMC_PLD_TCK")
	)
	(segment
		(start 121.852944 -78.383892)
		(end 121.20626 -77.737208)
		(width 0.12954)
		(layer "B.Cu")
		(net "JTAG_BMC_PLD_TCK")
	)
	(segment
		(start 114.297968 -71.984616)
		(end 114.297968 -70.751954)
		(width 0.12954)
		(layer "B.Cu")
		(net "JTAG_BMC_PLD_TCK")
	)
	(segment
		(start 114.297968 -70.751954)
		(end 114.3 -70.749922)
		(width 0.12954)
		(layer "B.Cu")
		(net "JTAG_BMC_PLD_TCK")
	)
	(segment
		(start 121.20626 -76.008484)
		(end 117.811804 -72.614028)
		(width 0.12954)
		(layer "B.Cu")
		(net "JTAG_BMC_PLD_TCK")
	)
	(segment
		(start 114.92738 -72.614028)
		(end 114.297968 -71.984616)
		(width 0.12954)
		(layer "B.Cu")
		(net "JTAG_BMC_PLD_TCK")
	)
	(segment
		(start 121.20626 -77.737208)
		(end 121.20626 -76.008484)
		(width 0.12954)
		(layer "B.Cu")
		(net "JTAG_BMC_PLD_TCK")
	)
	(segment
		(start 108.69676 -54.627018)
		(end 108.74883 -54.574948)
		(width 0.12954)
		(layer "F.Cu")
		(net "JTAG_BMC_PCH_TCK")
	)
	(segment
		(start 106.89971 -54.627018)
		(end 108.69676 -54.627018)
		(width 0.12954)
		(layer "F.Cu")
		(net "JTAG_BMC_PCH_TCK")
	)
	(segment
		(start 105.76941 -54.627018)
		(end 106.89971 -54.627018)
		(width 0.12954)
		(layer "F.Cu")
		(net "JTAG_BMC_PCH_TCK")
	)
	(segment
		(start 102.905306 -60.936632)
		(end 103.063548 -60.77839)
		(width 0.12954)
		(layer "F.Cu")
		(net "JTAG_BMC_PCH_TCK")
	)
	(segment
		(start 103.063548 -60.77839)
		(end 103.931212 -60.77839)
		(width 0.12954)
		(layer "F.Cu")
		(net "JTAG_BMC_PCH_TCK")
	)
	(via
		(at 106.89971 -54.627018)
		(size 0.508)
		(drill 0.254)
		(layers "F.Cu" "B.Cu")
		(net "JTAG_BMC_PCH_TCK")
	)
	(via
		(at 102.905306 -60.936632)
		(size 0.508)
		(drill 0.254)
		(layers "F.Cu" "B.Cu")
		(net "JTAG_BMC_PCH_TCK")
	)
	(segment
		(start 106.89971 -54.627018)
		(end 103.6574 -57.869328)
		(width 0.12954)
		(layer "B.Cu")
		(net "JTAG_BMC_PCH_TCK")
	)
	(segment
		(start 103.6574 -57.869328)
		(end 103.6574 -60.184538)
		(width 0.12954)
		(layer "B.Cu")
		(net "JTAG_BMC_PCH_TCK")
	)
	(segment
		(start 103.6574 -60.184538)
		(end 102.905306 -60.936632)
		(width 0.12954)
		(layer "B.Cu")
		(net "JTAG_BMC_PCH_TCK")
	)
	(segment
		(start 373.619268 -104.068372)
		(end 373.323358 -104.364282)
		(width 0.12954)
		(layer "F.Cu")
		(net "JTAG_BMC_DBP_TMS_R")
	)
	(segment
		(start 372.97233 -102.106984)
		(end 372.97233 -103.421434)
		(width 0.12954)
		(layer "F.Cu")
		(net "JTAG_BMC_DBP_TMS_R")
	)
	(segment
		(start 372.97233 -103.421434)
		(end 373.619268 -104.068372)
		(width 0.12954)
		(layer "F.Cu")
		(net "JTAG_BMC_DBP_TMS_R")
	)
	(segment
		(start 373.323358 -104.364282)
		(end 373.323358 -106.272584)
		(width 0.12954)
		(layer "F.Cu")
		(net "JTAG_BMC_DBP_TMS_R")
	)
	(segment
		(start 123.317 -74.621898)
		(end 124.229114 -74.621898)
		(width 0.12954)
		(layer "F.Cu")
		(net "JTAG_BMC_DBP_TMS_R")
	)
	(via
		(at 373.323358 -106.272584)
		(size 0.508)
		(drill 0.254)
		(layers "F.Cu" "B.Cu")
		(net "JTAG_BMC_DBP_TMS_R")
	)
	(via
		(at 373.619268 -104.068372)
		(size 0.508)
		(drill 0.254)
		(layers "F.Cu" "B.Cu")
		(net "JTAG_BMC_DBP_TMS_R")
	)
	(via
		(at 124.229114 -74.621898)
		(size 0.508)
		(drill 0.254)
		(layers "F.Cu" "B.Cu")
		(net "JTAG_BMC_DBP_TMS_R")
	)
	(segment
		(start 373.323358 -106.272584)
		(end 372.085362 -105.034588)
		(width 0.12954)
		(layer "B.Cu")
		(net "JTAG_BMC_DBP_TMS_R")
	)
	(segment
		(start 158.118556 -77.290168)
		(end 157.600396 -77.808328)
		(width 0.12954)
		(layer "B.Cu")
		(net "JTAG_BMC_DBP_TMS_R")
	)
	(segment
		(start 285.299404 -98.262948)
		(end 274.905724 -87.869268)
		(width 0.12954)
		(layer "B.Cu")
		(net "JTAG_BMC_DBP_TMS_R")
	)
	(segment
		(start 129.413 -75.275948)
		(end 128.46558 -75.275948)
		(width 0.12954)
		(layer "B.Cu")
		(net "JTAG_BMC_DBP_TMS_R")
	)
	(segment
		(start 176.07915 -82.739738)
		(end 171.102782 -80.678528)
		(width 0.12954)
		(layer "B.Cu")
		(net "JTAG_BMC_DBP_TMS_R")
	)
	(segment
		(start 274.905724 -87.869268)
		(end 258.491482 -87.869268)
		(width 0.12954)
		(layer "B.Cu")
		(net "JTAG_BMC_DBP_TMS_R")
	)
	(segment
		(start 133.37794 -79.240888)
		(end 129.413 -75.275948)
		(width 0.12954)
		(layer "B.Cu")
		(net "JTAG_BMC_DBP_TMS_R")
	)
	(segment
		(start 217.18905 -82.739738)
		(end 176.07915 -82.739738)
		(width 0.12954)
		(layer "B.Cu")
		(net "JTAG_BMC_DBP_TMS_R")
	)
	(segment
		(start 128.46558 -75.275948)
		(end 127.762 -75.979528)
		(width 0.12954)
		(layer "B.Cu")
		(net "JTAG_BMC_DBP_TMS_R")
	)
	(segment
		(start 361.26928 -98.262948)
		(end 285.299404 -98.262948)
		(width 0.12954)
		(layer "B.Cu")
		(net "JTAG_BMC_DBP_TMS_R")
	)
	(segment
		(start 145.59026 -79.240888)
		(end 133.37794 -79.240888)
		(width 0.12954)
		(layer "B.Cu")
		(net "JTAG_BMC_DBP_TMS_R")
	)
	(segment
		(start 160.871154 -77.290168)
		(end 158.118556 -77.290168)
		(width 0.12954)
		(layer "B.Cu")
		(net "JTAG_BMC_DBP_TMS_R")
	)
	(segment
		(start 368.04092 -105.034588)
		(end 361.26928 -98.262948)
		(width 0.12954)
		(layer "B.Cu")
		(net "JTAG_BMC_DBP_TMS_R")
	)
	(segment
		(start 126.45898 -75.979528)
		(end 125.10135 -74.621898)
		(width 0.12954)
		(layer "B.Cu")
		(net "JTAG_BMC_DBP_TMS_R")
	)
	(segment
		(start 125.10135 -74.621898)
		(end 124.229114 -74.621898)
		(width 0.12954)
		(layer "B.Cu")
		(net "JTAG_BMC_DBP_TMS_R")
	)
	(segment
		(start 248.723658 -90.49131)
		(end 240.267236 -90.49131)
		(width 0.12954)
		(layer "B.Cu")
		(net "JTAG_BMC_DBP_TMS_R")
	)
	(segment
		(start 147.02282 -77.808328)
		(end 145.59026 -79.240888)
		(width 0.12954)
		(layer "B.Cu")
		(net "JTAG_BMC_DBP_TMS_R")
	)
	(segment
		(start 163.13023 -79.549244)
		(end 160.871154 -77.290168)
		(width 0.12954)
		(layer "B.Cu")
		(net "JTAG_BMC_DBP_TMS_R")
	)
	(segment
		(start 240.267236 -90.49131)
		(end 238.748062 -91.120468)
		(width 0.12954)
		(layer "B.Cu")
		(net "JTAG_BMC_DBP_TMS_R")
	)
	(segment
		(start 372.085362 -105.034588)
		(end 368.04092 -105.034588)
		(width 0.12954)
		(layer "B.Cu")
		(net "JTAG_BMC_DBP_TMS_R")
	)
	(segment
		(start 127.762 -75.979528)
		(end 126.45898 -75.979528)
		(width 0.12954)
		(layer "B.Cu")
		(net "JTAG_BMC_DBP_TMS_R")
	)
	(segment
		(start 255.337056 -89.175844)
		(end 248.723658 -90.49131)
		(width 0.12954)
		(layer "B.Cu")
		(net "JTAG_BMC_DBP_TMS_R")
	)
	(segment
		(start 238.748062 -91.120468)
		(end 225.56978 -91.120468)
		(width 0.12954)
		(layer "B.Cu")
		(net "JTAG_BMC_DBP_TMS_R")
	)
	(segment
		(start 225.56978 -91.120468)
		(end 217.18905 -82.739738)
		(width 0.12954)
		(layer "B.Cu")
		(net "JTAG_BMC_DBP_TMS_R")
	)
	(segment
		(start 163.44392 -80.678528)
		(end 163.13023 -80.364838)
		(width 0.12954)
		(layer "B.Cu")
		(net "JTAG_BMC_DBP_TMS_R")
	)
	(segment
		(start 163.13023 -80.364838)
		(end 163.13023 -79.549244)
		(width 0.12954)
		(layer "B.Cu")
		(net "JTAG_BMC_DBP_TMS_R")
	)
	(segment
		(start 171.102782 -80.678528)
		(end 163.44392 -80.678528)
		(width 0.12954)
		(layer "B.Cu")
		(net "JTAG_BMC_DBP_TMS_R")
	)
	(segment
		(start 157.600396 -77.808328)
		(end 147.02282 -77.808328)
		(width 0.12954)
		(layer "B.Cu")
		(net "JTAG_BMC_DBP_TMS_R")
	)
	(segment
		(start 258.491482 -87.869268)
		(end 255.337056 -89.175844)
		(width 0.12954)
		(layer "B.Cu")
		(net "JTAG_BMC_DBP_TMS_R")
	)
	(segment
		(start 122.555 -76.412344)
		(end 121.852944 -77.113892)
		(width 0.12954)
		(layer "F.Cu")
		(net "JTAG_BMC_DBP_TMS")
	)
	(segment
		(start 121.852944 -77.113892)
		(end 121.46788 -77.498956)
		(width 0.12954)
		(layer "F.Cu")
		(net "JTAG_BMC_DBP_TMS")
	)
	(segment
		(start 123.317 -75.421998)
		(end 122.301 -75.421998)
		(width 0.12954)
		(layer "F.Cu")
		(net "JTAG_BMC_DBP_TMS")
	)
	(segment
		(start 121.46788 -77.498956)
		(end 119.546116 -77.498956)
		(width 0.12954)
		(layer "F.Cu")
		(net "JTAG_BMC_DBP_TMS")
	)
	(segment
		(start 122.301 -75.421998)
		(end 122.555 -75.675998)
		(width 0.12954)
		(layer "F.Cu")
		(net "JTAG_BMC_DBP_TMS")
	)
	(segment
		(start 122.555 -75.675998)
		(end 122.555 -76.412344)
		(width 0.12954)
		(layer "F.Cu")
		(net "JTAG_BMC_DBP_TMS")
	)
	(via
		(at 121.852944 -77.113892)
		(size 0.508)
		(drill 0.254)
		(layers "F.Cu" "B.Cu")
		(net "JTAG_BMC_DBP_TMS")
	)
	(segment
		(start 376.368564 -94.561152)
		(end 376.368564 -96.212152)
		(width 0.12954)
		(layer "F.Cu")
		(net "JTAG_BMC_DBP_TDO_R")
	)
	(segment
		(start 376.296936 -93.310202)
		(end 376.368564 -93.38183)
		(width 0.12954)
		(layer "F.Cu")
		(net "JTAG_BMC_DBP_TDO_R")
	)
	(segment
		(start 376.368564 -93.38183)
		(end 376.368564 -94.561152)
		(width 0.12954)
		(layer "F.Cu")
		(net "JTAG_BMC_DBP_TDO_R")
	)
	(via
		(at 376.368564 -94.561152)
		(size 0.508)
		(drill 0.254)
		(layers "F.Cu" "B.Cu")
		(net "JTAG_BMC_DBP_TDO_R")
	)
	(segment
		(start 376.296936 -91.868752)
		(end 376.296936 -92.510102)
		(width 0.12954)
		(layer "F.Cu")
		(net "JTAG_BMC_DBP_TDO")
	)
	(segment
		(start 128.029716 -78.321154)
		(end 128.800606 -78.321154)
		(width 0.12954)
		(layer "F.Cu")
		(net "JTAG_BMC_DBP_TDO")
	)
	(segment
		(start 128.800606 -78.321154)
		(end 129.066544 -78.587092)
		(width 0.12954)
		(layer "F.Cu")
		(net "JTAG_BMC_DBP_TDO")
	)
	(segment
		(start 129.066544 -78.587092)
		(end 129.116328 -78.636876)
		(width 0.12954)
		(layer "F.Cu")
		(net "JTAG_BMC_DBP_TDO")
	)
	(segment
		(start 129.116328 -78.636876)
		(end 129.116328 -80.112616)
		(width 0.12954)
		(layer "F.Cu")
		(net "JTAG_BMC_DBP_TDO")
	)
	(via
		(at 376.296936 -91.868752)
		(size 0.508)
		(drill 0.254)
		(layers "F.Cu" "B.Cu")
		(net "JTAG_BMC_DBP_TDO")
	)
	(via
		(at 129.066544 -78.587092)
		(size 0.508)
		(drill 0.254)
		(layers "F.Cu" "B.Cu")
		(net "JTAG_BMC_DBP_TDO")
	)
	(segment
		(start 376.92584 -96.515428)
		(end 376.92584 -92.497656)
		(width 0.12954)
		(layer "B.Cu")
		(net "JTAG_BMC_DBP_TDO")
	)
	(segment
		(start 249.162062 -91.3384)
		(end 255.86309 -90.005408)
		(width 0.12954)
		(layer "B.Cu")
		(net "JTAG_BMC_DBP_TDO")
	)
	(segment
		(start 284.988762 -99.012248)
		(end 355.83114 -99.012248)
		(width 0.12954)
		(layer "B.Cu")
		(net "JTAG_BMC_DBP_TDO")
	)
	(segment
		(start 274.595082 -88.618568)
		(end 284.988762 -99.012248)
		(width 0.12954)
		(layer "B.Cu")
		(net "JTAG_BMC_DBP_TDO")
	)
	(segment
		(start 161.05632 -79.35087)
		(end 163.144708 -81.439258)
		(width 0.12954)
		(layer "B.Cu")
		(net "JTAG_BMC_DBP_TDO")
	)
	(segment
		(start 130.51282 -80.033368)
		(end 145.857722 -80.033368)
		(width 0.12954)
		(layer "B.Cu")
		(net "JTAG_BMC_DBP_TDO")
	)
	(segment
		(start 170.819826 -81.439258)
		(end 175.768508 -83.489038)
		(width 0.12954)
		(layer "B.Cu")
		(net "JTAG_BMC_DBP_TDO")
	)
	(segment
		(start 381.26416 -107.526328)
		(end 381.26416 -100.853748)
		(width 0.12954)
		(layer "B.Cu")
		(net "JTAG_BMC_DBP_TDO")
	)
	(segment
		(start 159.123634 -79.807308)
		(end 159.580072 -79.35087)
		(width 0.12954)
		(layer "B.Cu")
		(net "JTAG_BMC_DBP_TDO")
	)
	(segment
		(start 225.259138 -91.869768)
		(end 238.99622 -91.869768)
		(width 0.12954)
		(layer "B.Cu")
		(net "JTAG_BMC_DBP_TDO")
	)
	(segment
		(start 155.22448 -78.557628)
		(end 156.47416 -79.807308)
		(width 0.12954)
		(layer "B.Cu")
		(net "JTAG_BMC_DBP_TDO")
	)
	(segment
		(start 379.13564 -109.654848)
		(end 381.26416 -107.526328)
		(width 0.12954)
		(layer "B.Cu")
		(net "JTAG_BMC_DBP_TDO")
	)
	(segment
		(start 255.86309 -90.005408)
		(end 259.210556 -88.618568)
		(width 0.12954)
		(layer "B.Cu")
		(net "JTAG_BMC_DBP_TDO")
	)
	(segment
		(start 238.99622 -91.869768)
		(end 240.279174 -91.3384)
		(width 0.12954)
		(layer "B.Cu")
		(net "JTAG_BMC_DBP_TDO")
	)
	(segment
		(start 381.26416 -100.853748)
		(end 376.92584 -96.515428)
		(width 0.12954)
		(layer "B.Cu")
		(net "JTAG_BMC_DBP_TDO")
	)
	(segment
		(start 216.878408 -83.489038)
		(end 225.259138 -91.869768)
		(width 0.12954)
		(layer "B.Cu")
		(net "JTAG_BMC_DBP_TDO")
	)
	(segment
		(start 366.47374 -109.654848)
		(end 379.13564 -109.654848)
		(width 0.12954)
		(layer "B.Cu")
		(net "JTAG_BMC_DBP_TDO")
	)
	(segment
		(start 175.768508 -83.489038)
		(end 216.878408 -83.489038)
		(width 0.12954)
		(layer "B.Cu")
		(net "JTAG_BMC_DBP_TDO")
	)
	(segment
		(start 240.279174 -91.3384)
		(end 249.162062 -91.3384)
		(width 0.12954)
		(layer "B.Cu")
		(net "JTAG_BMC_DBP_TDO")
	)
	(segment
		(start 145.857722 -80.033368)
		(end 147.333462 -78.557628)
		(width 0.12954)
		(layer "B.Cu")
		(net "JTAG_BMC_DBP_TDO")
	)
	(segment
		(start 159.580072 -79.35087)
		(end 161.05632 -79.35087)
		(width 0.12954)
		(layer "B.Cu")
		(net "JTAG_BMC_DBP_TDO")
	)
	(segment
		(start 156.47416 -79.807308)
		(end 159.123634 -79.807308)
		(width 0.12954)
		(layer "B.Cu")
		(net "JTAG_BMC_DBP_TDO")
	)
	(segment
		(start 355.83114 -99.012248)
		(end 366.47374 -109.654848)
		(width 0.12954)
		(layer "B.Cu")
		(net "JTAG_BMC_DBP_TDO")
	)
	(segment
		(start 129.066544 -78.587092)
		(end 130.51282 -80.033368)
		(width 0.12954)
		(layer "B.Cu")
		(net "JTAG_BMC_DBP_TDO")
	)
	(segment
		(start 163.144708 -81.439258)
		(end 170.819826 -81.439258)
		(width 0.12954)
		(layer "B.Cu")
		(net "JTAG_BMC_DBP_TDO")
	)
	(segment
		(start 147.333462 -78.557628)
		(end 155.22448 -78.557628)
		(width 0.12954)
		(layer "B.Cu")
		(net "JTAG_BMC_DBP_TDO")
	)
	(segment
		(start 259.210556 -88.618568)
		(end 274.595082 -88.618568)
		(width 0.12954)
		(layer "B.Cu")
		(net "JTAG_BMC_DBP_TDO")
	)
	(segment
		(start 376.92584 -92.497656)
		(end 376.296936 -91.868752)
		(width 0.12954)
		(layer "B.Cu")
		(net "JTAG_BMC_DBP_TDO")
	)
	(segment
		(start 128.9685 -75.707494)
		(end 128.9685 -75.224132)
		(width 0.12954)
		(layer "F.Cu")
		(net "JTAG_BMC_DBP_TDI_R")
	)
	(segment
		(start 372.322344 -103.801672)
		(end 372.322344 -102.106984)
		(width 0.12954)
		(layer "F.Cu")
		(net "JTAG_BMC_DBP_TDI_R")
	)
	(segment
		(start 129.159508 -75.898502)
		(end 128.9685 -75.707494)
		(width 0.12954)
		(layer "F.Cu")
		(net "JTAG_BMC_DBP_TDI_R")
	)
	(via
		(at 372.322344 -103.801672)
		(size 0.508)
		(drill 0.254)
		(layers "F.Cu" "B.Cu")
		(net "JTAG_BMC_DBP_TDI_R")
	)
	(via
		(at 129.159508 -75.898502)
		(size 0.508)
		(drill 0.254)
		(layers "F.Cu" "B.Cu")
		(net "JTAG_BMC_DBP_TDI_R")
	)
	(segment
		(start 373.200422 -105.107994)
		(end 374.045734 -105.107994)
		(width 0.12954)
		(layer "B.Cu")
		(net "JTAG_BMC_DBP_TDI_R")
	)
	(segment
		(start 366.31372 -107.203748)
		(end 357.74884 -98.638868)
		(width 0.12954)
		(layer "B.Cu")
		(net "JTAG_BMC_DBP_TDI_R")
	)
	(segment
		(start 248.7295 -90.936826)
		(end 240.162334 -90.936826)
		(width 0.12954)
		(layer "B.Cu")
		(net "JTAG_BMC_DBP_TDI_R")
	)
	(segment
		(start 374.45315 -107.203748)
		(end 366.31372 -107.203748)
		(width 0.12954)
		(layer "B.Cu")
		(net "JTAG_BMC_DBP_TDI_R")
	)
	(segment
		(start 357.74884 -98.638868)
		(end 285.143448 -98.638868)
		(width 0.12954)
		(layer "B.Cu")
		(net "JTAG_BMC_DBP_TDI_R")
	)
	(segment
		(start 160.23082 -78.402688)
		(end 159.59328 -77.765148)
		(width 0.12954)
		(layer "B.Cu")
		(net "JTAG_BMC_DBP_TDI_R")
	)
	(segment
		(start 159.59328 -77.765148)
		(end 158.198058 -77.765148)
		(width 0.12954)
		(layer "B.Cu")
		(net "JTAG_BMC_DBP_TDI_R")
	)
	(segment
		(start 175.923194 -83.115658)
		(end 171.011342 -81.081118)
		(width 0.12954)
		(layer "B.Cu")
		(net "JTAG_BMC_DBP_TDI_R")
	)
	(segment
		(start 372.322344 -104.229916)
		(end 373.200422 -105.107994)
		(width 0.12954)
		(layer "B.Cu")
		(net "JTAG_BMC_DBP_TDI_R")
	)
	(segment
		(start 157.778958 -78.184248)
		(end 147.178776 -78.184248)
		(width 0.12954)
		(layer "B.Cu")
		(net "JTAG_BMC_DBP_TDI_R")
	)
	(segment
		(start 160.636204 -78.402688)
		(end 160.23082 -78.402688)
		(width 0.12954)
		(layer "B.Cu")
		(net "JTAG_BMC_DBP_TDI_R")
	)
	(segment
		(start 163.314634 -81.081118)
		(end 160.636204 -78.402688)
		(width 0.12954)
		(layer "B.Cu")
		(net "JTAG_BMC_DBP_TDI_R")
	)
	(segment
		(start 374.900952 -106.755946)
		(end 374.45315 -107.203748)
		(width 0.12954)
		(layer "B.Cu")
		(net "JTAG_BMC_DBP_TDI_R")
	)
	(segment
		(start 274.749768 -88.245188)
		(end 259.012944 -88.245188)
		(width 0.12954)
		(layer "B.Cu")
		(net "JTAG_BMC_DBP_TDI_R")
	)
	(segment
		(start 238.811308 -91.496388)
		(end 225.413824 -91.496388)
		(width 0.12954)
		(layer "B.Cu")
		(net "JTAG_BMC_DBP_TDI_R")
	)
	(segment
		(start 171.011342 -81.081118)
		(end 163.314634 -81.081118)
		(width 0.12954)
		(layer "B.Cu")
		(net "JTAG_BMC_DBP_TDI_R")
	)
	(segment
		(start 217.033094 -83.115658)
		(end 175.923194 -83.115658)
		(width 0.12954)
		(layer "B.Cu")
		(net "JTAG_BMC_DBP_TDI_R")
	)
	(segment
		(start 374.045734 -105.107994)
		(end 374.900952 -105.963212)
		(width 0.12954)
		(layer "B.Cu")
		(net "JTAG_BMC_DBP_TDI_R")
	)
	(segment
		(start 372.322344 -103.801672)
		(end 372.322344 -104.229916)
		(width 0.12954)
		(layer "B.Cu")
		(net "JTAG_BMC_DBP_TDI_R")
	)
	(segment
		(start 225.413824 -91.496388)
		(end 217.033094 -83.115658)
		(width 0.12954)
		(layer "B.Cu")
		(net "JTAG_BMC_DBP_TDI_R")
	)
	(segment
		(start 256.011172 -89.488518)
		(end 248.7295 -90.936826)
		(width 0.12954)
		(layer "B.Cu")
		(net "JTAG_BMC_DBP_TDI_R")
	)
	(segment
		(start 145.763996 -79.599028)
		(end 132.860034 -79.599028)
		(width 0.12954)
		(layer "B.Cu")
		(net "JTAG_BMC_DBP_TDI_R")
	)
	(segment
		(start 158.198058 -77.765148)
		(end 157.778958 -78.184248)
		(width 0.12954)
		(layer "B.Cu")
		(net "JTAG_BMC_DBP_TDI_R")
	)
	(segment
		(start 374.900952 -105.963212)
		(end 374.900952 -106.755946)
		(width 0.12954)
		(layer "B.Cu")
		(net "JTAG_BMC_DBP_TDI_R")
	)
	(segment
		(start 132.860034 -79.599028)
		(end 129.159508 -75.898502)
		(width 0.12954)
		(layer "B.Cu")
		(net "JTAG_BMC_DBP_TDI_R")
	)
	(segment
		(start 285.143448 -98.638868)
		(end 274.749768 -88.245188)
		(width 0.12954)
		(layer "B.Cu")
		(net "JTAG_BMC_DBP_TDI_R")
	)
	(segment
		(start 259.012944 -88.245188)
		(end 256.011172 -89.488518)
		(width 0.12954)
		(layer "B.Cu")
		(net "JTAG_BMC_DBP_TDI_R")
	)
	(segment
		(start 147.178776 -78.184248)
		(end 145.763996 -79.599028)
		(width 0.12954)
		(layer "B.Cu")
		(net "JTAG_BMC_DBP_TDI_R")
	)
	(segment
		(start 240.162334 -90.936826)
		(end 238.811308 -91.496388)
		(width 0.12954)
		(layer "B.Cu")
		(net "JTAG_BMC_DBP_TDI_R")
	)
	(segment
		(start 128.9685 -74.450448)
		(end 128.524 -74.894948)
		(width 0.12954)
		(layer "F.Cu")
		(net "JTAG_BMC_DBP_TDI")
	)
	(segment
		(start 129.159 -77.053948)
		(end 128.891792 -77.321156)
		(width 0.12954)
		(layer "F.Cu")
		(net "JTAG_BMC_DBP_TDI")
	)
	(segment
		(start 129.17805 -73.370948)
		(end 129.17805 -74.214482)
		(width 0.12954)
		(layer "F.Cu")
		(net "JTAG_BMC_DBP_TDI")
	)
	(segment
		(start 128.524 -74.894948)
		(end 128.524 -76.03998)
		(width 0.12954)
		(layer "F.Cu")
		(net "JTAG_BMC_DBP_TDI")
	)
	(segment
		(start 129.159 -76.67498)
		(end 129.159 -77.053948)
		(width 0.12954)
		(layer "F.Cu")
		(net "JTAG_BMC_DBP_TDI")
	)
	(segment
		(start 128.891792 -77.321156)
		(end 128.029716 -77.321156)
		(width 0.12954)
		(layer "F.Cu")
		(net "JTAG_BMC_DBP_TDI")
	)
	(segment
		(start 129.17805 -74.214482)
		(end 128.9685 -74.424032)
		(width 0.12954)
		(layer "F.Cu")
		(net "JTAG_BMC_DBP_TDI")
	)
	(segment
		(start 128.524 -76.03998)
		(end 129.159 -76.67498)
		(width 0.12954)
		(layer "F.Cu")
		(net "JTAG_BMC_DBP_TDI")
	)
	(segment
		(start 128.9685 -74.424032)
		(end 128.9685 -74.450448)
		(width 0.12954)
		(layer "F.Cu")
		(net "JTAG_BMC_DBP_TDI")
	)
	(via
		(at 129.159 -77.053948)
		(size 0.508)
		(drill 0.254)
		(layers "F.Cu" "B.Cu")
		(net "JTAG_BMC_DBP_TDI")
	)
	(segment
		(start 108.32846 -62.042548)
		(end 112.9284 -62.042548)
		(width 0.12954)
		(layer "F.Cu")
		(net "JTAG_BMC_DBP_TCK")
	)
	(segment
		(start 112.9284 -62.042548)
		(end 114.9858 -64.099948)
		(width 0.12954)
		(layer "F.Cu")
		(net "JTAG_BMC_DBP_TCK")
	)
	(segment
		(start 122.63628 -78.788768)
		(end 122.1232 -79.301848)
		(width 0.12954)
		(layer "F.Cu")
		(net "JTAG_BMC_DBP_TCK")
	)
	(segment
		(start 121.285 -64.099948)
		(end 122.47372 -65.288668)
		(width 0.12954)
		(layer "F.Cu")
		(net "JTAG_BMC_DBP_TCK")
	)
	(segment
		(start 105.0544 -59.832748)
		(end 105.0544 -61.737748)
		(width 0.12954)
		(layer "F.Cu")
		(net "JTAG_BMC_DBP_TCK")
	)
	(segment
		(start 124.95022 -73.607168)
		(end 124.95022 -75.362308)
		(width 0.12954)
		(layer "F.Cu")
		(net "JTAG_BMC_DBP_TCK")
	)
	(segment
		(start 124.95022 -75.362308)
		(end 122.63628 -77.676248)
		(width 0.12954)
		(layer "F.Cu")
		(net "JTAG_BMC_DBP_TCK")
	)
	(segment
		(start 122.47372 -65.288668)
		(end 122.47372 -69.352668)
		(width 0.12954)
		(layer "F.Cu")
		(net "JTAG_BMC_DBP_TCK")
	)
	(segment
		(start 105.0544 -61.737748)
		(end 105.4608 -62.144148)
		(width 0.12954)
		(layer "F.Cu")
		(net "JTAG_BMC_DBP_TCK")
	)
	(segment
		(start 123.19 -71.846948)
		(end 124.95022 -73.607168)
		(width 0.12954)
		(layer "F.Cu")
		(net "JTAG_BMC_DBP_TCK")
	)
	(segment
		(start 122.63628 -77.676248)
		(end 122.63628 -78.788768)
		(width 0.12954)
		(layer "F.Cu")
		(net "JTAG_BMC_DBP_TCK")
	)
	(segment
		(start 122.47372 -69.352668)
		(end 123.19 -70.068948)
		(width 0.12954)
		(layer "F.Cu")
		(net "JTAG_BMC_DBP_TCK")
	)
	(segment
		(start 108.22686 -62.144148)
		(end 108.32846 -62.042548)
		(width 0.12954)
		(layer "F.Cu")
		(net "JTAG_BMC_DBP_TCK")
	)
	(segment
		(start 122.1232 -79.301848)
		(end 121.1199 -79.301848)
		(width 0.12954)
		(layer "F.Cu")
		(net "JTAG_BMC_DBP_TCK")
	)
	(segment
		(start 121.1199 -79.301848)
		(end 120.317006 -78.498954)
		(width 0.12954)
		(layer "F.Cu")
		(net "JTAG_BMC_DBP_TCK")
	)
	(segment
		(start 120.317006 -78.498954)
		(end 119.546116 -78.498954)
		(width 0.12954)
		(layer "F.Cu")
		(net "JTAG_BMC_DBP_TCK")
	)
	(segment
		(start 105.931208 -59.478418)
		(end 105.40873 -59.478418)
		(width 0.12954)
		(layer "F.Cu")
		(net "JTAG_BMC_DBP_TCK")
	)
	(segment
		(start 114.9858 -64.099948)
		(end 121.285 -64.099948)
		(width 0.12954)
		(layer "F.Cu")
		(net "JTAG_BMC_DBP_TCK")
	)
	(segment
		(start 105.40873 -59.478418)
		(end 105.0544 -59.832748)
		(width 0.12954)
		(layer "F.Cu")
		(net "JTAG_BMC_DBP_TCK")
	)
	(segment
		(start 123.19 -70.068948)
		(end 123.19 -71.846948)
		(width 0.12954)
		(layer "F.Cu")
		(net "JTAG_BMC_DBP_TCK")
	)
	(segment
		(start 105.4608 -62.144148)
		(end 108.22686 -62.144148)
		(width 0.12954)
		(layer "F.Cu")
		(net "JTAG_BMC_DBP_TCK")
	)
	(via
		(at 108.32846 -62.042548)
		(size 0.508)
		(drill 0.254)
		(layers "F.Cu" "B.Cu")
		(net "JTAG_BMC_DBP_TCK")
	)
	(segment
		(start 143.124428 -10.369804)
		(end 143.063468 -10.308844)
		(width 0.12954)
		(layer "F.Cu")
		(net "JTAG_BMC_DBP_PREQ_N")
	)
	(segment
		(start 370.021358 -106.323384)
		(end 370.021358 -106.932984)
		(width 0.12954)
		(layer "F.Cu")
		(net "JTAG_BMC_DBP_PREQ_N")
	)
	(segment
		(start 143.063468 -10.308844)
		(end 142.896844 -10.308844)
		(width 0.12954)
		(layer "F.Cu")
		(net "JTAG_BMC_DBP_PREQ_N")
	)
	(segment
		(start 142.346934 -10.858754)
		(end 142.346934 -13.600176)
		(width 0.12954)
		(layer "F.Cu")
		(net "JTAG_BMC_DBP_PREQ_N")
	)
	(segment
		(start 142.896844 -10.308844)
		(end 142.346934 -10.858754)
		(width 0.12954)
		(layer "F.Cu")
		(net "JTAG_BMC_DBP_PREQ_N")
	)
	(via
		(at 370.021358 -106.323384)
		(size 0.508)
		(drill 0.254)
		(layers "F.Cu" "B.Cu")
		(net "JTAG_BMC_DBP_PREQ_N")
	)
	(via
		(at 143.124428 -10.369804)
		(size 0.508)
		(drill 0.254)
		(layers "F.Cu" "B.Cu")
		(net "JTAG_BMC_DBP_PREQ_N")
	)
	(via
		(at 147.701 -10.632948)
		(size 0.508)
		(drill 0.254)
		(layers "F.Cu" "B.Cu")
		(net "JTAG_BMC_DBP_PREQ_N")
	)
	(segment
		(start 145.438114 -9.739884)
		(end 145.415 -9.762998)
		(width 0.12954)
		(layer "B.Cu")
		(net "JTAG_BMC_DBP_PREQ_N")
	)
	(segment
		(start 145.85696 -9.739884)
		(end 145.438114 -9.739884)
		(width 0.12954)
		(layer "B.Cu")
		(net "JTAG_BMC_DBP_PREQ_N")
	)
	(segment
		(start 145.415 -9.762998)
		(end 144.399 -9.762998)
		(width 0.12954)
		(layer "B.Cu")
		(net "JTAG_BMC_DBP_PREQ_N")
	)
	(segment
		(start 145.880074 -9.762998)
		(end 145.85696 -9.739884)
		(width 0.12954)
		(layer "B.Cu")
		(net "JTAG_BMC_DBP_PREQ_N")
	)
	(segment
		(start 147.701 -10.632948)
		(end 146.83105 -9.762998)
		(width 0.12954)
		(layer "B.Cu")
		(net "JTAG_BMC_DBP_PREQ_N")
	)
	(segment
		(start 143.124428 -10.369804)
		(end 143.731234 -9.762998)
		(width 0.12954)
		(layer "B.Cu")
		(net "JTAG_BMC_DBP_PREQ_N")
	)
	(segment
		(start 146.83105 -9.762998)
		(end 145.880074 -9.762998)
		(width 0.12954)
		(layer "B.Cu")
		(net "JTAG_BMC_DBP_PREQ_N")
	)
	(segment
		(start 143.731234 -9.762998)
		(end 144.399 -9.762998)
		(width 0.12954)
		(layer "B.Cu")
		(net "JTAG_BMC_DBP_PREQ_N")
	)
	(segment
		(start 178.363372 -9.116568)
		(end 183.430672 -14.183868)
		(width 0.127)
		(layer "In13.Cu")
		(net "JTAG_BMC_DBP_PREQ_N")
	)
	(segment
		(start 391.737342 -82.331306)
		(end 375.16054 -89.197688)
		(width 0.127)
		(layer "In13.Cu")
		(net "JTAG_BMC_DBP_PREQ_N")
	)
	(segment
		(start 211.676996 -19.934428)
		(end 215.517476 -19.934428)
		(width 0.127)
		(layer "In13.Cu")
		(net "JTAG_BMC_DBP_PREQ_N")
	)
	(segment
		(start 272.639282 -31.940754)
		(end 275.06168 -29.518356)
		(width 0.127)
		(layer "In13.Cu")
		(net "JTAG_BMC_DBP_PREQ_N")
	)
	(segment
		(start 263.328912 -35.797998)
		(end 272.639282 -31.940754)
		(width 0.127)
		(layer "In13.Cu")
		(net "JTAG_BMC_DBP_PREQ_N")
	)
	(segment
		(start 396.77086 -50.143156)
		(end 396.77086 -64.277748)
		(width 0.127)
		(layer "In13.Cu")
		(net "JTAG_BMC_DBP_PREQ_N")
	)
	(segment
		(start 167.841168 -9.116568)
		(end 178.363372 -9.116568)
		(width 0.127)
		(layer "In13.Cu")
		(net "JTAG_BMC_DBP_PREQ_N")
	)
	(segment
		(start 275.06168 -29.518356)
		(end 307.624988 -16.030448)
		(width 0.127)
		(layer "In13.Cu")
		(net "JTAG_BMC_DBP_PREQ_N")
	)
	(segment
		(start 394.46454 -79.604108)
		(end 391.737342 -82.331306)
		(width 0.127)
		(layer "In13.Cu")
		(net "JTAG_BMC_DBP_PREQ_N")
	)
	(segment
		(start 208.026 -16.283432)
		(end 211.676996 -19.934428)
		(width 0.127)
		(layer "In13.Cu")
		(net "JTAG_BMC_DBP_PREQ_N")
	)
	(segment
		(start 256.492248 -38.91026)
		(end 262.850884 -36.276026)
		(width 0.127)
		(layer "In13.Cu")
		(net "JTAG_BMC_DBP_PREQ_N")
	)
	(segment
		(start 196.071236 -16.283432)
		(end 208.026 -16.283432)
		(width 0.127)
		(layer "In13.Cu")
		(net "JTAG_BMC_DBP_PREQ_N")
	)
	(segment
		(start 238.633 -41.697148)
		(end 242.49634 -41.697148)
		(width 0.127)
		(layer "In13.Cu")
		(net "JTAG_BMC_DBP_PREQ_N")
	)
	(segment
		(start 341.970868 -16.030448)
		(end 358.286304 -22.788626)
		(width 0.127)
		(layer "In13.Cu")
		(net "JTAG_BMC_DBP_PREQ_N")
	)
	(segment
		(start 220.746574 -35.012122)
		(end 223.7232 -37.988748)
		(width 0.127)
		(layer "In13.Cu")
		(net "JTAG_BMC_DBP_PREQ_N")
	)
	(segment
		(start 255.80848 -38.91026)
		(end 256.492248 -38.91026)
		(width 0.127)
		(layer "In13.Cu")
		(net "JTAG_BMC_DBP_PREQ_N")
	)
	(segment
		(start 223.7232 -37.988748)
		(end 236.0676 -37.988748)
		(width 0.127)
		(layer "In13.Cu")
		(net "JTAG_BMC_DBP_PREQ_N")
	)
	(segment
		(start 307.624988 -16.030448)
		(end 341.970868 -16.030448)
		(width 0.127)
		(layer "In13.Cu")
		(net "JTAG_BMC_DBP_PREQ_N")
	)
	(segment
		(start 254.032512 -39.660576)
		(end 255.058164 -39.660576)
		(width 0.127)
		(layer "In13.Cu")
		(net "JTAG_BMC_DBP_PREQ_N")
	)
	(segment
		(start 371.88648 -92.471748)
		(end 370.10086 -92.471748)
		(width 0.127)
		(layer "In13.Cu")
		(net "JTAG_BMC_DBP_PREQ_N")
	)
	(segment
		(start 262.850884 -36.276026)
		(end 263.328912 -35.797998)
		(width 0.127)
		(layer "In13.Cu")
		(net "JTAG_BMC_DBP_PREQ_N")
	)
	(segment
		(start 358.286304 -22.788626)
		(end 391.828274 -45.20057)
		(width 0.127)
		(layer "In13.Cu")
		(net "JTAG_BMC_DBP_PREQ_N")
	)
	(segment
		(start 253.11608 -40.577008)
		(end 254.032512 -39.660576)
		(width 0.127)
		(layer "In13.Cu")
		(net "JTAG_BMC_DBP_PREQ_N")
	)
	(segment
		(start 148.15058 -10.183368)
		(end 166.774368 -10.183368)
		(width 0.127)
		(layer "In13.Cu")
		(net "JTAG_BMC_DBP_PREQ_N")
	)
	(segment
		(start 220.746574 -25.163526)
		(end 220.746574 -35.012122)
		(width 0.127)
		(layer "In13.Cu")
		(net "JTAG_BMC_DBP_PREQ_N")
	)
	(segment
		(start 375.16054 -89.197688)
		(end 371.88648 -92.471748)
		(width 0.127)
		(layer "In13.Cu")
		(net "JTAG_BMC_DBP_PREQ_N")
	)
	(segment
		(start 237.2995 -40.363648)
		(end 238.633 -41.697148)
		(width 0.127)
		(layer "In13.Cu")
		(net "JTAG_BMC_DBP_PREQ_N")
	)
	(segment
		(start 193.971672 -14.183868)
		(end 196.071236 -16.283432)
		(width 0.127)
		(layer "In13.Cu")
		(net "JTAG_BMC_DBP_PREQ_N")
	)
	(segment
		(start 368.83848 -105.140506)
		(end 370.021358 -106.323384)
		(width 0.127)
		(layer "In13.Cu")
		(net "JTAG_BMC_DBP_PREQ_N")
	)
	(segment
		(start 394.46454 -66.584068)
		(end 394.46454 -79.604108)
		(width 0.127)
		(layer "In13.Cu")
		(net "JTAG_BMC_DBP_PREQ_N")
	)
	(segment
		(start 255.058164 -39.660576)
		(end 255.80848 -38.91026)
		(width 0.127)
		(layer "In13.Cu")
		(net "JTAG_BMC_DBP_PREQ_N")
	)
	(segment
		(start 237.2995 -39.220648)
		(end 237.2995 -40.363648)
		(width 0.127)
		(layer "In13.Cu")
		(net "JTAG_BMC_DBP_PREQ_N")
	)
	(segment
		(start 215.517476 -19.934428)
		(end 220.746574 -25.163526)
		(width 0.127)
		(layer "In13.Cu")
		(net "JTAG_BMC_DBP_PREQ_N")
	)
	(segment
		(start 147.701 -10.632948)
		(end 148.15058 -10.183368)
		(width 0.127)
		(layer "In13.Cu")
		(net "JTAG_BMC_DBP_PREQ_N")
	)
	(segment
		(start 243.61648 -40.577008)
		(end 253.11608 -40.577008)
		(width 0.127)
		(layer "In13.Cu")
		(net "JTAG_BMC_DBP_PREQ_N")
	)
	(segment
		(start 370.10086 -92.471748)
		(end 368.83848 -93.734128)
		(width 0.127)
		(layer "In13.Cu")
		(net "JTAG_BMC_DBP_PREQ_N")
	)
	(segment
		(start 368.83848 -93.734128)
		(end 368.83848 -105.140506)
		(width 0.127)
		(layer "In13.Cu")
		(net "JTAG_BMC_DBP_PREQ_N")
	)
	(segment
		(start 396.77086 -64.277748)
		(end 394.46454 -66.584068)
		(width 0.127)
		(layer "In13.Cu")
		(net "JTAG_BMC_DBP_PREQ_N")
	)
	(segment
		(start 166.774368 -10.183368)
		(end 167.841168 -9.116568)
		(width 0.127)
		(layer "In13.Cu")
		(net "JTAG_BMC_DBP_PREQ_N")
	)
	(segment
		(start 242.49634 -41.697148)
		(end 243.61648 -40.577008)
		(width 0.127)
		(layer "In13.Cu")
		(net "JTAG_BMC_DBP_PREQ_N")
	)
	(segment
		(start 391.828274 -45.20057)
		(end 396.77086 -50.143156)
		(width 0.127)
		(layer "In13.Cu")
		(net "JTAG_BMC_DBP_PREQ_N")
	)
	(segment
		(start 236.0676 -37.988748)
		(end 237.2995 -39.220648)
		(width 0.127)
		(layer "In13.Cu")
		(net "JTAG_BMC_DBP_PREQ_N")
	)
	(segment
		(start 183.430672 -14.183868)
		(end 193.971672 -14.183868)
		(width 0.127)
		(layer "In13.Cu")
		(net "JTAG_BMC_DBP_PREQ_N")
	)
	(segment
		(start 97.71253 -55.463948)
		(end 96.97593 -56.200548)
		(width 0.12954)
		(layer "F.Cu")
		(net "JTAG_BMC_CPU_TCK")
	)
	(segment
		(start 96.97593 -56.200548)
		(end 96.97593 -56.225948)
		(width 0.12954)
		(layer "F.Cu")
		(net "JTAG_BMC_CPU_TCK")
	)
	(segment
		(start 98.921824 -55.277004)
		(end 98.73488 -55.463948)
		(width 0.12954)
		(layer "F.Cu")
		(net "JTAG_BMC_CPU_TCK")
	)
	(segment
		(start 99.92741 -55.277004)
		(end 98.921824 -55.277004)
		(width 0.12954)
		(layer "F.Cu")
		(net "JTAG_BMC_CPU_TCK")
	)
	(segment
		(start 98.73488 -55.463948)
		(end 97.71253 -55.463948)
		(width 0.12954)
		(layer "F.Cu")
		(net "JTAG_BMC_CPU_TCK")
	)
	(segment
		(start 103.931212 -59.478418)
		(end 102.2858 -59.478418)
		(width 0.12954)
		(layer "F.Cu")
		(net "JTAG_BMC_CPU_TCK")
	)
	(via
		(at 98.73488 -55.463948)
		(size 0.508)
		(drill 0.254)
		(layers "F.Cu" "B.Cu")
		(net "JTAG_BMC_CPU_TCK")
	)
	(via
		(at 102.2858 -59.478418)
		(size 0.508)
		(drill 0.254)
		(layers "F.Cu" "B.Cu")
		(net "JTAG_BMC_CPU_TCK")
	)
	(segment
		(start 102.2858 -59.014868)
		(end 98.73488 -55.463948)
		(width 0.12954)
		(layer "B.Cu")
		(net "JTAG_BMC_CPU_TCK")
	)
	(segment
		(start 102.2858 -59.478418)
		(end 102.2858 -59.014868)
		(width 0.12954)
		(layer "B.Cu")
		(net "JTAG_BMC_CPU_TCK")
	)
	(segment
		(start 210.11515 -107.01655)
		(end 210.3882 -107.01655)
		(width 0.12954)
		(layer "F.Cu")
		(net "IRQ_UV_DETECT_N")
	)
	(segment
		(start 203.151994 -106.436668)
		(end 207.583532 -106.436668)
		(width 0.12954)
		(layer "F.Cu")
		(net "IRQ_UV_DETECT_N")
	)
	(segment
		(start 195.94576 -104.323388)
		(end 198.618348 -104.323388)
		(width 0.12954)
		(layer "F.Cu")
		(net "IRQ_UV_DETECT_N")
	)
	(segment
		(start 198.618348 -104.323388)
		(end 200.70318 -106.40822)
		(width 0.12954)
		(layer "F.Cu")
		(net "IRQ_UV_DETECT_N")
	)
	(segment
		(start 203.123546 -106.40822)
		(end 203.151994 -106.436668)
		(width 0.12954)
		(layer "F.Cu")
		(net "IRQ_UV_DETECT_N")
	)
	(segment
		(start 208.153 -106.2482)
		(end 209.3468 -106.2482)
		(width 0.12954)
		(layer "F.Cu")
		(net "IRQ_UV_DETECT_N")
	)
	(segment
		(start 210.3882 -107.01655)
		(end 211.4296 -107.01655)
		(width 0.12954)
		(layer "F.Cu")
		(net "IRQ_UV_DETECT_N")
	)
	(segment
		(start 211.13496 -105.67416)
		(end 211.4296 -105.9688)
		(width 0.12954)
		(layer "F.Cu")
		(net "IRQ_UV_DETECT_N")
	)
	(segment
		(start 216.492074 -96.103948)
		(end 218.29395 -96.103948)
		(width 0.12954)
		(layer "F.Cu")
		(net "IRQ_UV_DETECT_N")
	)
	(segment
		(start 208.9912 -105.45826)
		(end 209.2071 -105.67416)
		(width 0.12954)
		(layer "F.Cu")
		(net "IRQ_UV_DETECT_N")
	)
	(segment
		(start 200.70318 -106.40822)
		(end 203.123546 -106.40822)
		(width 0.12954)
		(layer "F.Cu")
		(net "IRQ_UV_DETECT_N")
	)
	(segment
		(start 209.2071 -105.67416)
		(end 211.13496 -105.67416)
		(width 0.12954)
		(layer "F.Cu")
		(net "IRQ_UV_DETECT_N")
	)
	(segment
		(start 211.4296 -105.9688)
		(end 211.4296 -107.01655)
		(width 0.12954)
		(layer "F.Cu")
		(net "IRQ_UV_DETECT_N")
	)
	(segment
		(start 209.3468 -106.2482)
		(end 210.11515 -107.01655)
		(width 0.12954)
		(layer "F.Cu")
		(net "IRQ_UV_DETECT_N")
	)
	(segment
		(start 216.492074 -96.103948)
		(end 215.6714 -96.103948)
		(width 0.12954)
		(layer "F.Cu")
		(net "IRQ_UV_DETECT_N")
	)
	(segment
		(start 215.0364 -102.235)
		(end 209.319368 -102.235)
		(width 0.12954)
		(layer "F.Cu")
		(net "IRQ_UV_DETECT_N")
	)
	(segment
		(start 195.30822 -103.685848)
		(end 195.94576 -104.323388)
		(width 0.12954)
		(layer "F.Cu")
		(net "IRQ_UV_DETECT_N")
	)
	(segment
		(start 209.319368 -102.235)
		(end 208.9912 -102.563168)
		(width 0.12954)
		(layer "F.Cu")
		(net "IRQ_UV_DETECT_N")
	)
	(segment
		(start 215.4174 -101.854)
		(end 215.0364 -102.235)
		(width 0.12954)
		(layer "F.Cu")
		(net "IRQ_UV_DETECT_N")
	)
	(segment
		(start 208.9912 -102.563168)
		(end 208.9912 -105.45826)
		(width 0.12954)
		(layer "F.Cu")
		(net "IRQ_UV_DETECT_N")
	)
	(segment
		(start 215.6714 -96.103948)
		(end 215.4174 -96.357948)
		(width 0.12954)
		(layer "F.Cu")
		(net "IRQ_UV_DETECT_N")
	)
	(segment
		(start 194.00393 -103.685848)
		(end 195.30822 -103.685848)
		(width 0.12954)
		(layer "F.Cu")
		(net "IRQ_UV_DETECT_N")
	)
	(segment
		(start 207.772 -106.2482)
		(end 208.153 -106.2482)
		(width 0.12954)
		(layer "F.Cu")
		(net "IRQ_UV_DETECT_N")
	)
	(segment
		(start 207.583532 -106.436668)
		(end 207.772 -106.2482)
		(width 0.12954)
		(layer "F.Cu")
		(net "IRQ_UV_DETECT_N")
	)
	(segment
		(start 215.4174 -96.357948)
		(end 215.4174 -101.854)
		(width 0.12954)
		(layer "F.Cu")
		(net "IRQ_UV_DETECT_N")
	)
	(via
		(at 208.153 -106.2482)
		(size 0.762)
		(drill 0.381)
		(layers "F.Cu" "B.Cu")
		(net "IRQ_UV_DETECT_N")
	)
	(segment
		(start 191.7954 -116.070888)
		(end 190.57366 -114.849148)
		(width 0.12954)
		(layer "F.Cu")
		(net "IRQ_TPM_SPI_N")
	)
	(segment
		(start 327.142602 -53.757068)
		(end 327.295256 -53.625242)
		(width 0.0889)
		(layer "F.Cu")
		(net "IRQ_TPM_SPI_N")
	)
	(segment
		(start 192.20942 -117.445028)
		(end 191.7954 -117.031008)
		(width 0.12954)
		(layer "F.Cu")
		(net "IRQ_TPM_SPI_N")
	)
	(segment
		(start 320.590672 -55.235348)
		(end 321.277996 -55.235348)
		(width 0.12954)
		(layer "F.Cu")
		(net "IRQ_TPM_SPI_N")
	)
	(segment
		(start 323.754242 -54.836568)
		(end 324.997318 -53.593492)
		(width 0.0889)
		(layer "F.Cu")
		(net "IRQ_TPM_SPI_N")
	)
	(segment
		(start 199.06996 -117.445028)
		(end 192.20942 -117.445028)
		(width 0.12954)
		(layer "F.Cu")
		(net "IRQ_TPM_SPI_N")
	)
	(segment
		(start 326.944736 -53.804058)
		(end 327.04786 -53.804058)
		(width 0.0889)
		(layer "F.Cu")
		(net "IRQ_TPM_SPI_N")
	)
	(segment
		(start 326.760078 -53.681122)
		(end 326.944736 -53.804058)
		(width 0.0889)
		(layer "F.Cu")
		(net "IRQ_TPM_SPI_N")
	)
	(segment
		(start 327.467722 -53.452776)
		(end 327.829672 -53.452776)
		(width 0.0889)
		(layer "F.Cu")
		(net "IRQ_TPM_SPI_N")
	)
	(segment
		(start 190.57366 -114.849148)
		(end 190.299848 -114.575336)
		(width 0.12954)
		(layer "F.Cu")
		(net "IRQ_TPM_SPI_N")
	)
	(segment
		(start 326.739504 -53.660548)
		(end 326.760078 -53.681122)
		(width 0.0889)
		(layer "F.Cu")
		(net "IRQ_TPM_SPI_N")
	)
	(segment
		(start 325.833994 -53.593492)
		(end 325.90105 -53.660548)
		(width 0.0889)
		(layer "F.Cu")
		(net "IRQ_TPM_SPI_N")
	)
	(segment
		(start 322.342256 -55.235348)
		(end 322.741036 -54.836568)
		(width 0.12954)
		(layer "F.Cu")
		(net "IRQ_TPM_SPI_N")
	)
	(segment
		(start 191.7954 -117.031008)
		(end 191.7954 -116.070888)
		(width 0.12954)
		(layer "F.Cu")
		(net "IRQ_TPM_SPI_N")
	)
	(segment
		(start 327.295256 -53.625242)
		(end 327.467722 -53.452776)
		(width 0.0889)
		(layer "F.Cu")
		(net "IRQ_TPM_SPI_N")
	)
	(segment
		(start 325.90105 -53.660548)
		(end 326.739504 -53.660548)
		(width 0.0889)
		(layer "F.Cu")
		(net "IRQ_TPM_SPI_N")
	)
	(segment
		(start 199.69988 -118.074948)
		(end 199.06996 -117.445028)
		(width 0.12954)
		(layer "F.Cu")
		(net "IRQ_TPM_SPI_N")
	)
	(segment
		(start 190.299848 -114.575336)
		(end 186.955684 -114.575336)
		(width 0.12954)
		(layer "F.Cu")
		(net "IRQ_TPM_SPI_N")
	)
	(segment
		(start 321.277996 -55.235348)
		(end 322.342256 -55.235348)
		(width 0.12954)
		(layer "F.Cu")
		(net "IRQ_TPM_SPI_N")
	)
	(segment
		(start 327.829672 -53.452776)
		(end 327.829926 -53.452522)
		(width 0.0889)
		(layer "F.Cu")
		(net "IRQ_TPM_SPI_N")
	)
	(segment
		(start 324.997318 -53.593492)
		(end 325.833994 -53.593492)
		(width 0.0889)
		(layer "F.Cu")
		(net "IRQ_TPM_SPI_N")
	)
	(segment
		(start 322.741036 -54.836568)
		(end 323.754242 -54.836568)
		(width 0.12954)
		(layer "F.Cu")
		(net "IRQ_TPM_SPI_N")
	)
	(segment
		(start 327.04786 -53.804058)
		(end 327.142602 -53.757068)
		(width 0.0889)
		(layer "F.Cu")
		(net "IRQ_TPM_SPI_N")
	)
	(via
		(at 198.73468 -90.160348)
		(size 0.508)
		(drill 0.254)
		(layers "F.Cu" "B.Cu")
		(net "IRQ_TPM_SPI_N")
	)
	(via
		(at 244.60708 -67.274948)
		(size 0.508)
		(drill 0.254)
		(layers "F.Cu" "B.Cu")
		(net "IRQ_TPM_SPI_N")
	)
	(via
		(at 321.277996 -55.235348)
		(size 0.508)
		(drill 0.254)
		(layers "F.Cu" "B.Cu")
		(net "IRQ_TPM_SPI_N")
	)
	(via
		(at 190.57366 -114.849148)
		(size 0.762)
		(drill 0.381)
		(layers "F.Cu" "B.Cu")
		(net "IRQ_TPM_SPI_N")
	)
	(via
		(at 199.69988 -118.074948)
		(size 0.508)
		(drill 0.254)
		(layers "F.Cu" "B.Cu")
		(net "IRQ_TPM_SPI_N")
	)
	(segment
		(start 317.55588 -54.193948)
		(end 317.55588 -53.304948)
		(width 0.127)
		(layer "In6.Cu")
		(net "IRQ_TPM_SPI_N")
	)
	(segment
		(start 317.55588 -53.304948)
		(end 318.11214 -52.748688)
		(width 0.127)
		(layer "In6.Cu")
		(net "IRQ_TPM_SPI_N")
	)
	(segment
		(start 316.15888 -54.955948)
		(end 316.79388 -54.955948)
		(width 0.127)
		(layer "In6.Cu")
		(net "IRQ_TPM_SPI_N")
	)
	(segment
		(start 244.60708 -66.667888)
		(end 245.27002 -66.004948)
		(width 0.127)
		(layer "In6.Cu")
		(net "IRQ_TPM_SPI_N")
	)
	(segment
		(start 290.581842 -54.8894)
		(end 290.95319 -55.260748)
		(width 0.127)
		(layer "In6.Cu")
		(net "IRQ_TPM_SPI_N")
	)
	(segment
		(start 260.064758 -66.004948)
		(end 263.873234 -64.427354)
		(width 0.127)
		(layer "In6.Cu")
		(net "IRQ_TPM_SPI_N")
	)
	(segment
		(start 302.26635 -56.664098)
		(end 302.5648 -56.962548)
		(width 0.127)
		(layer "In6.Cu")
		(net "IRQ_TPM_SPI_N")
	)
	(segment
		(start 304.31994 -56.962548)
		(end 306.0192 -55.263288)
		(width 0.127)
		(layer "In6.Cu")
		(net "IRQ_TPM_SPI_N")
	)
	(segment
		(start 301.52975 -56.664098)
		(end 302.26635 -56.664098)
		(width 0.127)
		(layer "In6.Cu")
		(net "IRQ_TPM_SPI_N")
	)
	(segment
		(start 309.93588 -55.971948)
		(end 313.23788 -55.971948)
		(width 0.127)
		(layer "In6.Cu")
		(net "IRQ_TPM_SPI_N")
	)
	(segment
		(start 321.277996 -53.725064)
		(end 321.277996 -55.235348)
		(width 0.127)
		(layer "In6.Cu")
		(net "IRQ_TPM_SPI_N")
	)
	(segment
		(start 290.95319 -55.260748)
		(end 294.9702 -55.260748)
		(width 0.127)
		(layer "In6.Cu")
		(net "IRQ_TPM_SPI_N")
	)
	(segment
		(start 244.60708 -67.274948)
		(end 244.60708 -66.667888)
		(width 0.127)
		(layer "In6.Cu")
		(net "IRQ_TPM_SPI_N")
	)
	(segment
		(start 263.873234 -64.427354)
		(end 266.30884 -61.991748)
		(width 0.127)
		(layer "In6.Cu")
		(net "IRQ_TPM_SPI_N")
	)
	(segment
		(start 294.9702 -55.260748)
		(end 296.7482 -57.038748)
		(width 0.127)
		(layer "In6.Cu")
		(net "IRQ_TPM_SPI_N")
	)
	(segment
		(start 315.39688 -55.717948)
		(end 316.15888 -54.955948)
		(width 0.127)
		(layer "In6.Cu")
		(net "IRQ_TPM_SPI_N")
	)
	(segment
		(start 296.7482 -57.038748)
		(end 301.1551 -57.038748)
		(width 0.127)
		(layer "In6.Cu")
		(net "IRQ_TPM_SPI_N")
	)
	(segment
		(start 320.30162 -52.748688)
		(end 321.277996 -53.725064)
		(width 0.127)
		(layer "In6.Cu")
		(net "IRQ_TPM_SPI_N")
	)
	(segment
		(start 276.590252 -60.773564)
		(end 282.474416 -54.8894)
		(width 0.127)
		(layer "In6.Cu")
		(net "IRQ_TPM_SPI_N")
	)
	(segment
		(start 313.49188 -55.717948)
		(end 315.39688 -55.717948)
		(width 0.127)
		(layer "In6.Cu")
		(net "IRQ_TPM_SPI_N")
	)
	(segment
		(start 301.1551 -57.038748)
		(end 301.52975 -56.664098)
		(width 0.127)
		(layer "In6.Cu")
		(net "IRQ_TPM_SPI_N")
	)
	(segment
		(start 282.474416 -54.8894)
		(end 290.581842 -54.8894)
		(width 0.127)
		(layer "In6.Cu")
		(net "IRQ_TPM_SPI_N")
	)
	(segment
		(start 316.79388 -54.955948)
		(end 317.55588 -54.193948)
		(width 0.127)
		(layer "In6.Cu")
		(net "IRQ_TPM_SPI_N")
	)
	(segment
		(start 306.0192 -55.263288)
		(end 309.22722 -55.263288)
		(width 0.127)
		(layer "In6.Cu")
		(net "IRQ_TPM_SPI_N")
	)
	(segment
		(start 274.757642 -60.773564)
		(end 276.590252 -60.773564)
		(width 0.127)
		(layer "In6.Cu")
		(net "IRQ_TPM_SPI_N")
	)
	(segment
		(start 302.5648 -56.962548)
		(end 304.31994 -56.962548)
		(width 0.127)
		(layer "In6.Cu")
		(net "IRQ_TPM_SPI_N")
	)
	(segment
		(start 245.27002 -66.004948)
		(end 260.064758 -66.004948)
		(width 0.127)
		(layer "In6.Cu")
		(net "IRQ_TPM_SPI_N")
	)
	(segment
		(start 318.11214 -52.748688)
		(end 320.30162 -52.748688)
		(width 0.127)
		(layer "In6.Cu")
		(net "IRQ_TPM_SPI_N")
	)
	(segment
		(start 273.539458 -61.991748)
		(end 274.757642 -60.773564)
		(width 0.127)
		(layer "In6.Cu")
		(net "IRQ_TPM_SPI_N")
	)
	(segment
		(start 266.30884 -61.991748)
		(end 273.539458 -61.991748)
		(width 0.127)
		(layer "In6.Cu")
		(net "IRQ_TPM_SPI_N")
	)
	(segment
		(start 313.23788 -55.971948)
		(end 313.49188 -55.717948)
		(width 0.127)
		(layer "In6.Cu")
		(net "IRQ_TPM_SPI_N")
	)
	(segment
		(start 309.22722 -55.263288)
		(end 309.93588 -55.971948)
		(width 0.127)
		(layer "In6.Cu")
		(net "IRQ_TPM_SPI_N")
	)
	(segment
		(start 198.73468 -94.40545)
		(end 190.82004 -102.32009)
		(width 0.127)
		(layer "In13.Cu")
		(net "IRQ_TPM_SPI_N")
	)
	(segment
		(start 199.14108 -111.570008)
		(end 199.14108 -117.516148)
		(width 0.127)
		(layer "In13.Cu")
		(net "IRQ_TPM_SPI_N")
	)
	(segment
		(start 190.82004 -107.317032)
		(end 194.079876 -110.576868)
		(width 0.127)
		(layer "In13.Cu")
		(net "IRQ_TPM_SPI_N")
	)
	(segment
		(start 198.73468 -90.160348)
		(end 198.73468 -94.40545)
		(width 0.127)
		(layer "In13.Cu")
		(net "IRQ_TPM_SPI_N")
	)
	(segment
		(start 198.14794 -110.576868)
		(end 199.14108 -111.570008)
		(width 0.127)
		(layer "In13.Cu")
		(net "IRQ_TPM_SPI_N")
	)
	(segment
		(start 190.82004 -102.32009)
		(end 190.82004 -107.317032)
		(width 0.127)
		(layer "In13.Cu")
		(net "IRQ_TPM_SPI_N")
	)
	(segment
		(start 194.079876 -110.576868)
		(end 198.14794 -110.576868)
		(width 0.127)
		(layer "In13.Cu")
		(net "IRQ_TPM_SPI_N")
	)
	(segment
		(start 199.14108 -117.516148)
		(end 199.69988 -118.074948)
		(width 0.127)
		(layer "In13.Cu")
		(net "IRQ_TPM_SPI_N")
	)
	(segment
		(start 233.547412 -69.317616)
		(end 222.02648 -80.838548)
		(width 0.127)
		(layer "In15.Cu")
		(net "IRQ_TPM_SPI_N")
	)
	(segment
		(start 242.564412 -69.317616)
		(end 233.547412 -69.317616)
		(width 0.127)
		(layer "In15.Cu")
		(net "IRQ_TPM_SPI_N")
	)
	(segment
		(start 200.74128 -80.838548)
		(end 198.73468 -82.845148)
		(width 0.127)
		(layer "In15.Cu")
		(net "IRQ_TPM_SPI_N")
	)
	(segment
		(start 244.60708 -67.274948)
		(end 242.564412 -69.317616)
		(width 0.127)
		(layer "In15.Cu")
		(net "IRQ_TPM_SPI_N")
	)
	(segment
		(start 222.02648 -80.838548)
		(end 200.74128 -80.838548)
		(width 0.127)
		(layer "In15.Cu")
		(net "IRQ_TPM_SPI_N")
	)
	(segment
		(start 198.73468 -82.845148)
		(end 198.73468 -90.160348)
		(width 0.127)
		(layer "In15.Cu")
		(net "IRQ_TPM_SPI_N")
	)
	(segment
		(start 170.155616 -110.575344)
		(end 169.755566 -110.975394)
		(width 0.12954)
		(layer "F.Cu")
		(net "IRQ_SML1_PMBUS_PLD_ALERT_N")
	)
	(via
		(at 303.4792 -36.350448)
		(size 0.508)
		(drill 0.254)
		(layers "F.Cu" "B.Cu")
		(net "IRQ_SML1_PMBUS_PLD_ALERT_N")
	)
	(via
		(at 169.755566 -110.975394)
		(size 0.4572)
		(drill 0.254)
		(layers "F.Cu" "B.Cu")
		(net "IRQ_SML1_PMBUS_PLD_ALERT_N")
	)
	(via
		(at 308.20868 -36.820348)
		(size 0.6604)
		(drill 0.3302)
		(layers "F.Cu" "B.Cu")
		(net "IRQ_SML1_PMBUS_PLD_ALERT_N")
	)
	(segment
		(start 308.20868 -36.820348)
		(end 308.71668 -36.312348)
		(width 0.12954)
		(layer "B.Cu")
		(net "IRQ_SML1_PMBUS_PLD_ALERT_N")
	)
	(segment
		(start 311.535572 -36.312348)
		(end 312.043572 -36.820348)
		(width 0.12954)
		(layer "B.Cu")
		(net "IRQ_SML1_PMBUS_PLD_ALERT_N")
	)
	(segment
		(start 303.4792 -36.350448)
		(end 307.73878 -36.350448)
		(width 0.12954)
		(layer "B.Cu")
		(net "IRQ_SML1_PMBUS_PLD_ALERT_N")
	)
	(segment
		(start 307.73878 -36.350448)
		(end 308.20868 -36.820348)
		(width 0.12954)
		(layer "B.Cu")
		(net "IRQ_SML1_PMBUS_PLD_ALERT_N")
	)
	(segment
		(start 308.71668 -36.312348)
		(end 311.535572 -36.312348)
		(width 0.12954)
		(layer "B.Cu")
		(net "IRQ_SML1_PMBUS_PLD_ALERT_N")
	)
	(segment
		(start 291.2999 -46.413928)
		(end 292.75786 -44.955968)
		(width 0.127)
		(layer "In13.Cu")
		(net "IRQ_SML1_PMBUS_PLD_ALERT_N")
	)
	(segment
		(start 168.9481 -99.18954)
		(end 168.948354 -99.189286)
		(width 0.127)
		(layer "In13.Cu")
		(net "IRQ_SML1_PMBUS_PLD_ALERT_N")
	)
	(segment
		(start 303.73828 -37.719508)
		(end 303.73828 -36.609528)
		(width 0.127)
		(layer "In13.Cu")
		(net "IRQ_SML1_PMBUS_PLD_ALERT_N")
	)
	(segment
		(start 292.75786 -44.955968)
		(end 293.7129 -44.955968)
		(width 0.127)
		(layer "In13.Cu")
		(net "IRQ_SML1_PMBUS_PLD_ALERT_N")
	)
	(segment
		(start 283.99486 -74.412348)
		(end 283.99486 -54.674008)
		(width 0.127)
		(layer "In13.Cu")
		(net "IRQ_SML1_PMBUS_PLD_ALERT_N")
	)
	(segment
		(start 170.701208 -89.28354)
		(end 175.907192 -89.28354)
		(width 0.127)
		(layer "In13.Cu")
		(net "IRQ_SML1_PMBUS_PLD_ALERT_N")
	)
	(segment
		(start 168.948354 -99.189286)
		(end 168.948354 -91.036394)
		(width 0.127)
		(layer "In13.Cu")
		(net "IRQ_SML1_PMBUS_PLD_ALERT_N")
	)
	(segment
		(start 168.45788 -99.680268)
		(end 168.9481 -99.190048)
		(width 0.127)
		(layer "In13.Cu")
		(net "IRQ_SML1_PMBUS_PLD_ALERT_N")
	)
	(segment
		(start 303.73828 -36.609528)
		(end 303.4792 -36.350448)
		(width 0.127)
		(layer "In13.Cu")
		(net "IRQ_SML1_PMBUS_PLD_ALERT_N")
	)
	(segment
		(start 168.948354 -91.036394)
		(end 170.701208 -89.28354)
		(width 0.127)
		(layer "In13.Cu")
		(net "IRQ_SML1_PMBUS_PLD_ALERT_N")
	)
	(segment
		(start 168.45788 -108.468668)
		(end 168.45788 -99.680268)
		(width 0.127)
		(layer "In13.Cu")
		(net "IRQ_SML1_PMBUS_PLD_ALERT_N")
	)
	(segment
		(start 291.2999 -47.368968)
		(end 291.2999 -46.413928)
		(width 0.127)
		(layer "In13.Cu")
		(net "IRQ_SML1_PMBUS_PLD_ALERT_N")
	)
	(segment
		(start 175.907192 -89.28354)
		(end 181.245764 -83.944968)
		(width 0.127)
		(layer "In13.Cu")
		(net "IRQ_SML1_PMBUS_PLD_ALERT_N")
	)
	(segment
		(start 297.38066 -41.288208)
		(end 300.16958 -41.288208)
		(width 0.127)
		(layer "In13.Cu")
		(net "IRQ_SML1_PMBUS_PLD_ALERT_N")
	)
	(segment
		(start 181.245764 -83.944968)
		(end 219.502736 -83.944968)
		(width 0.127)
		(layer "In13.Cu")
		(net "IRQ_SML1_PMBUS_PLD_ALERT_N")
	)
	(segment
		(start 219.502736 -83.944968)
		(end 222.784416 -87.226648)
		(width 0.127)
		(layer "In13.Cu")
		(net "IRQ_SML1_PMBUS_PLD_ALERT_N")
	)
	(segment
		(start 300.16958 -41.288208)
		(end 303.73828 -37.719508)
		(width 0.127)
		(layer "In13.Cu")
		(net "IRQ_SML1_PMBUS_PLD_ALERT_N")
	)
	(segment
		(start 243.675662 -81.81975)
		(end 276.587458 -81.81975)
		(width 0.127)
		(layer "In13.Cu")
		(net "IRQ_SML1_PMBUS_PLD_ALERT_N")
	)
	(segment
		(start 168.9481 -99.190048)
		(end 168.9481 -99.18954)
		(width 0.127)
		(layer "In13.Cu")
		(net "IRQ_SML1_PMBUS_PLD_ALERT_N")
	)
	(segment
		(start 238.268764 -87.226648)
		(end 243.675662 -81.81975)
		(width 0.127)
		(layer "In13.Cu")
		(net "IRQ_SML1_PMBUS_PLD_ALERT_N")
	)
	(segment
		(start 222.784416 -87.226648)
		(end 238.268764 -87.226648)
		(width 0.127)
		(layer "In13.Cu")
		(net "IRQ_SML1_PMBUS_PLD_ALERT_N")
	)
	(segment
		(start 276.587458 -81.81975)
		(end 283.99486 -74.412348)
		(width 0.127)
		(layer "In13.Cu")
		(net "IRQ_SML1_PMBUS_PLD_ALERT_N")
	)
	(segment
		(start 293.7129 -44.955968)
		(end 297.38066 -41.288208)
		(width 0.127)
		(layer "In13.Cu")
		(net "IRQ_SML1_PMBUS_PLD_ALERT_N")
	)
	(segment
		(start 283.99486 -54.674008)
		(end 291.2999 -47.368968)
		(width 0.127)
		(layer "In13.Cu")
		(net "IRQ_SML1_PMBUS_PLD_ALERT_N")
	)
	(segment
		(start 169.755566 -110.975394)
		(end 169.755566 -109.766354)
		(width 0.127)
		(layer "In13.Cu")
		(net "IRQ_SML1_PMBUS_PLD_ALERT_N")
	)
	(segment
		(start 169.755566 -109.766354)
		(end 168.45788 -108.468668)
		(width 0.127)
		(layer "In13.Cu")
		(net "IRQ_SML1_PMBUS_PLD_ALERT_N")
	)
	(segment
		(start 172.555662 -110.575344)
		(end 172.155612 -110.175294)
		(width 0.12954)
		(layer "F.Cu")
		(net "IRQ_SML1_PMBUS_BMC_ALERT_N")
	)
	(via
		(at 306.500276 -35.436048)
		(size 0.508)
		(drill 0.254)
		(layers "F.Cu" "B.Cu")
		(net "IRQ_SML1_PMBUS_BMC_ALERT_N")
	)
	(via
		(at 172.155612 -110.175294)
		(size 0.4572)
		(drill 0.254)
		(layers "F.Cu" "B.Cu")
		(net "IRQ_SML1_PMBUS_BMC_ALERT_N")
	)
	(segment
		(start 306.500276 -35.436048)
		(end 309.682896 -35.436048)
		(width 0.12954)
		(layer "B.Cu")
		(net "IRQ_SML1_PMBUS_BMC_ALERT_N")
	)
	(segment
		(start 312.043572 -35.409124)
		(end 312.043572 -35.804348)
		(width 0.12954)
		(layer "B.Cu")
		(net "IRQ_SML1_PMBUS_BMC_ALERT_N")
	)
	(segment
		(start 309.682896 -35.436048)
		(end 309.888636 -35.230308)
		(width 0.12954)
		(layer "B.Cu")
		(net "IRQ_SML1_PMBUS_BMC_ALERT_N")
	)
	(segment
		(start 309.888636 -35.230308)
		(end 311.864756 -35.230308)
		(width 0.12954)
		(layer "B.Cu")
		(net "IRQ_SML1_PMBUS_BMC_ALERT_N")
	)
	(segment
		(start 311.864756 -35.230308)
		(end 312.043572 -35.409124)
		(width 0.12954)
		(layer "B.Cu")
		(net "IRQ_SML1_PMBUS_BMC_ALERT_N")
	)
	(segment
		(start 182.96382 -86.103968)
		(end 177.04054 -92.027248)
		(width 0.127)
		(layer "In13.Cu")
		(net "IRQ_SML1_PMBUS_BMC_ALERT_N")
	)
	(segment
		(start 293.18966 -49.040288)
		(end 293.18966 -50.305208)
		(width 0.127)
		(layer "In13.Cu")
		(net "IRQ_SML1_PMBUS_BMC_ALERT_N")
	)
	(segment
		(start 307.2892 -41.303448)
		(end 302.4505 -46.142148)
		(width 0.127)
		(layer "In13.Cu")
		(net "IRQ_SML1_PMBUS_BMC_ALERT_N")
	)
	(segment
		(start 297.35272 -46.142148)
		(end 295.98112 -47.513748)
		(width 0.127)
		(layer "In13.Cu")
		(net "IRQ_SML1_PMBUS_BMC_ALERT_N")
	)
	(segment
		(start 277.744174 -83.97875)
		(end 244.832378 -83.97875)
		(width 0.127)
		(layer "In13.Cu")
		(net "IRQ_SML1_PMBUS_BMC_ALERT_N")
	)
	(segment
		(start 306.500276 -35.436048)
		(end 307.2892 -36.224972)
		(width 0.127)
		(layer "In13.Cu")
		(net "IRQ_SML1_PMBUS_BMC_ALERT_N")
	)
	(segment
		(start 221.812866 -89.570814)
		(end 218.34602 -86.103968)
		(width 0.127)
		(layer "In13.Cu")
		(net "IRQ_SML1_PMBUS_BMC_ALERT_N")
	)
	(segment
		(start 294.7162 -47.513748)
		(end 293.18966 -49.040288)
		(width 0.127)
		(layer "In13.Cu")
		(net "IRQ_SML1_PMBUS_BMC_ALERT_N")
	)
	(segment
		(start 171.99483 -98.36531)
		(end 171.99483 -101.759766)
		(width 0.127)
		(layer "In13.Cu")
		(net "IRQ_SML1_PMBUS_BMC_ALERT_N")
	)
	(segment
		(start 288.847784 -54.647084)
		(end 288.847784 -61.073538)
		(width 0.127)
		(layer "In13.Cu")
		(net "IRQ_SML1_PMBUS_BMC_ALERT_N")
	)
	(segment
		(start 171.99483 -101.759766)
		(end 171.37888 -102.375716)
		(width 0.127)
		(layer "In13.Cu")
		(net "IRQ_SML1_PMBUS_BMC_ALERT_N")
	)
	(segment
		(start 171.37888 -104.813608)
		(end 171.75226 -105.186988)
		(width 0.127)
		(layer "In13.Cu")
		(net "IRQ_SML1_PMBUS_BMC_ALERT_N")
	)
	(segment
		(start 295.98112 -47.513748)
		(end 294.7162 -47.513748)
		(width 0.127)
		(layer "In13.Cu")
		(net "IRQ_SML1_PMBUS_BMC_ALERT_N")
	)
	(segment
		(start 173.67758 -92.027248)
		(end 173.41596 -92.288868)
		(width 0.127)
		(layer "In13.Cu")
		(net "IRQ_SML1_PMBUS_BMC_ALERT_N")
	)
	(segment
		(start 286.58058 -75.142344)
		(end 277.744174 -83.97875)
		(width 0.127)
		(layer "In13.Cu")
		(net "IRQ_SML1_PMBUS_BMC_ALERT_N")
	)
	(segment
		(start 171.37888 -102.375716)
		(end 171.37888 -104.813608)
		(width 0.127)
		(layer "In13.Cu")
		(net "IRQ_SML1_PMBUS_BMC_ALERT_N")
	)
	(segment
		(start 173.41596 -92.64904)
		(end 171.2468 -94.8182)
		(width 0.127)
		(layer "In13.Cu")
		(net "IRQ_SML1_PMBUS_BMC_ALERT_N")
	)
	(segment
		(start 302.4505 -46.142148)
		(end 297.35272 -46.142148)
		(width 0.127)
		(layer "In13.Cu")
		(net "IRQ_SML1_PMBUS_BMC_ALERT_N")
	)
	(segment
		(start 173.41596 -92.288868)
		(end 173.41596 -92.64904)
		(width 0.127)
		(layer "In13.Cu")
		(net "IRQ_SML1_PMBUS_BMC_ALERT_N")
	)
	(segment
		(start 244.832378 -83.97875)
		(end 239.240314 -89.570814)
		(width 0.127)
		(layer "In13.Cu")
		(net "IRQ_SML1_PMBUS_BMC_ALERT_N")
	)
	(segment
		(start 239.240314 -89.570814)
		(end 221.812866 -89.570814)
		(width 0.127)
		(layer "In13.Cu")
		(net "IRQ_SML1_PMBUS_BMC_ALERT_N")
	)
	(segment
		(start 307.2892 -36.224972)
		(end 307.2892 -41.303448)
		(width 0.127)
		(layer "In13.Cu")
		(net "IRQ_SML1_PMBUS_BMC_ALERT_N")
	)
	(segment
		(start 286.58058 -63.340742)
		(end 286.58058 -75.142344)
		(width 0.127)
		(layer "In13.Cu")
		(net "IRQ_SML1_PMBUS_BMC_ALERT_N")
	)
	(segment
		(start 171.75226 -109.771942)
		(end 172.155612 -110.175294)
		(width 0.127)
		(layer "In13.Cu")
		(net "IRQ_SML1_PMBUS_BMC_ALERT_N")
	)
	(segment
		(start 171.2468 -94.8182)
		(end 171.2468 -97.61728)
		(width 0.127)
		(layer "In13.Cu")
		(net "IRQ_SML1_PMBUS_BMC_ALERT_N")
	)
	(segment
		(start 218.34602 -86.103968)
		(end 182.96382 -86.103968)
		(width 0.127)
		(layer "In13.Cu")
		(net "IRQ_SML1_PMBUS_BMC_ALERT_N")
	)
	(segment
		(start 171.75226 -105.186988)
		(end 171.75226 -109.771942)
		(width 0.127)
		(layer "In13.Cu")
		(net "IRQ_SML1_PMBUS_BMC_ALERT_N")
	)
	(segment
		(start 293.18966 -50.305208)
		(end 288.847784 -54.647084)
		(width 0.127)
		(layer "In13.Cu")
		(net "IRQ_SML1_PMBUS_BMC_ALERT_N")
	)
	(segment
		(start 171.2468 -97.61728)
		(end 171.99483 -98.36531)
		(width 0.127)
		(layer "In13.Cu")
		(net "IRQ_SML1_PMBUS_BMC_ALERT_N")
	)
	(segment
		(start 177.04054 -92.027248)
		(end 173.67758 -92.027248)
		(width 0.127)
		(layer "In13.Cu")
		(net "IRQ_SML1_PMBUS_BMC_ALERT_N")
	)
	(segment
		(start 288.847784 -61.073538)
		(end 286.58058 -63.340742)
		(width 0.127)
		(layer "In13.Cu")
		(net "IRQ_SML1_PMBUS_BMC_ALERT_N")
	)
	(segment
		(start 27.401266 -54.99989)
		(end 27.41676 -55.015384)
		(width 0.12954)
		(layer "F.Cu")
		(net "IRQ_SML1_PMBUS_ALERT_R_N")
	)
	(segment
		(start 24.60752 -54.99989)
		(end 27.401266 -54.99989)
		(width 0.12954)
		(layer "F.Cu")
		(net "IRQ_SML1_PMBUS_ALERT_R_N")
	)
	(segment
		(start 20.024852 -54.99989)
		(end 24.60752 -54.99989)
		(width 0.12954)
		(layer "F.Cu")
		(net "IRQ_SML1_PMBUS_ALERT_R_N")
	)
	(via
		(at 24.60752 -54.99989)
		(size 0.762)
		(drill 0.381)
		(layers "F.Cu" "B.Cu")
		(net "IRQ_SML1_PMBUS_ALERT_R_N")
	)
	(segment
		(start 326.889364 -43.749468)
		(end 327.131172 -43.749468)
		(width 0.0889)
		(layer "F.Cu")
		(net "IRQ_SML1_PMBUS_ALERT_N")
	)
	(segment
		(start 322.575174 -42.833798)
		(end 322.950078 -42.988992)
		(width 0.0889)
		(layer "F.Cu")
		(net "IRQ_SML1_PMBUS_ALERT_N")
	)
	(segment
		(start 289.47999 -387.39191)
		(end 289.47999 -388.349998)
		(width 0.10668)
		(layer "F.Cu")
		(net "IRQ_SML1_PMBUS_ALERT_N")
	)
	(segment
		(start 319.693036 -40.66032)
		(end 320.342006 -41.30929)
		(width 0.12954)
		(layer "F.Cu")
		(net "IRQ_SML1_PMBUS_ALERT_N")
	)
	(segment
		(start 318.120776 -39.393368)
		(end 319.012316 -39.393368)
		(width 0.12954)
		(layer "F.Cu")
		(net "IRQ_SML1_PMBUS_ALERT_N")
	)
	(segment
		(start 319.012316 -39.393368)
		(end 319.693036 -40.074088)
		(width 0.12954)
		(layer "F.Cu")
		(net "IRQ_SML1_PMBUS_ALERT_N")
	)
	(segment
		(start 28.21686 -55.015384)
		(end 28.82646 -55.015384)
		(width 0.12954)
		(layer "F.Cu")
		(net "IRQ_SML1_PMBUS_ALERT_N")
	)
	(segment
		(start 320.342006 -41.30929)
		(end 321.286886 -41.700704)
		(width 0.12954)
		(layer "F.Cu")
		(net "IRQ_SML1_PMBUS_ALERT_N")
	)
	(segment
		(start 193.78041 -116.804948)
		(end 194.39001 -116.804948)
		(width 0.12954)
		(layer "F.Cu")
		(net "IRQ_SML1_PMBUS_ALERT_N")
	)
	(segment
		(start 322.950078 -42.988992)
		(end 323.40169 -42.988992)
		(width 0.0889)
		(layer "F.Cu")
		(net "IRQ_SML1_PMBUS_ALERT_N")
	)
	(segment
		(start 324.072504 -43.659806)
		(end 326.754744 -43.659806)
		(width 0.0889)
		(layer "F.Cu")
		(net "IRQ_SML1_PMBUS_ALERT_N")
	)
	(segment
		(start 321.286886 -41.700704)
		(end 322.309998 -42.723816)
		(width 0.12954)
		(layer "F.Cu")
		(net "IRQ_SML1_PMBUS_ALERT_N")
	)
	(segment
		(start 326.754744 -43.659806)
		(end 326.889364 -43.749468)
		(width 0.0889)
		(layer "F.Cu")
		(net "IRQ_SML1_PMBUS_ALERT_N")
	)
	(segment
		(start 289.22218 -387.1341)
		(end 289.47999 -387.39191)
		(width 0.10668)
		(layer "F.Cu")
		(net "IRQ_SML1_PMBUS_ALERT_N")
	)
	(segment
		(start 313.459622 -36.820348)
		(end 314.208922 -37.569648)
		(width 0.12954)
		(layer "F.Cu")
		(net "IRQ_SML1_PMBUS_ALERT_N")
	)
	(segment
		(start 327.295256 -43.620182)
		(end 327.467468 -43.44797)
		(width 0.0889)
		(layer "F.Cu")
		(net "IRQ_SML1_PMBUS_ALERT_N")
	)
	(segment
		(start 317.071756 -38.344348)
		(end 318.120776 -39.393368)
		(width 0.12954)
		(layer "F.Cu")
		(net "IRQ_SML1_PMBUS_ALERT_N")
	)
	(segment
		(start 289.16122 -387.1341)
		(end 289.22218 -387.1341)
		(width 0.10668)
		(layer "F.Cu")
		(net "IRQ_SML1_PMBUS_ALERT_N")
	)
	(segment
		(start 327.164954 -43.732704)
		(end 327.295256 -43.620182)
		(width 0.0889)
		(layer "F.Cu")
		(net "IRQ_SML1_PMBUS_ALERT_N")
	)
	(segment
		(start 314.9727 -37.569648)
		(end 315.7474 -38.344348)
		(width 0.12954)
		(layer "F.Cu")
		(net "IRQ_SML1_PMBUS_ALERT_N")
	)
	(segment
		(start 319.693036 -40.074088)
		(end 319.693036 -40.66032)
		(width 0.12954)
		(layer "F.Cu")
		(net "IRQ_SML1_PMBUS_ALERT_N")
	)
	(segment
		(start 322.309998 -42.723816)
		(end 322.575174 -42.833798)
		(width 0.12954)
		(layer "F.Cu")
		(net "IRQ_SML1_PMBUS_ALERT_N")
	)
	(segment
		(start 323.40169 -42.988992)
		(end 324.072504 -43.659806)
		(width 0.0889)
		(layer "F.Cu")
		(net "IRQ_SML1_PMBUS_ALERT_N")
	)
	(segment
		(start 315.7474 -38.344348)
		(end 317.071756 -38.344348)
		(width 0.12954)
		(layer "F.Cu")
		(net "IRQ_SML1_PMBUS_ALERT_N")
	)
	(segment
		(start 327.467468 -43.44797)
		(end 327.829926 -43.44797)
		(width 0.0889)
		(layer "F.Cu")
		(net "IRQ_SML1_PMBUS_ALERT_N")
	)
	(segment
		(start 327.131172 -43.749468)
		(end 327.164954 -43.732704)
		(width 0.0889)
		(layer "F.Cu")
		(net "IRQ_SML1_PMBUS_ALERT_N")
	)
	(segment
		(start 314.208922 -37.569648)
		(end 314.9727 -37.569648)
		(width 0.12954)
		(layer "F.Cu")
		(net "IRQ_SML1_PMBUS_ALERT_N")
	)
	(via
		(at 201.98588 -90.134948)
		(size 0.508)
		(drill 0.254)
		(layers "F.Cu" "B.Cu")
		(net "IRQ_SML1_PMBUS_ALERT_N")
	)
	(via
		(at 289.16122 -387.1341)
		(size 0.508)
		(drill 0.254)
		(layers "F.Cu" "B.Cu")
		(net "IRQ_SML1_PMBUS_ALERT_N")
	)
	(via
		(at 194.39001 -116.804948)
		(size 0.508)
		(drill 0.254)
		(layers "F.Cu" "B.Cu")
		(net "IRQ_SML1_PMBUS_ALERT_N")
	)
	(via
		(at 213.26856 -114.201448)
		(size 0.508)
		(drill 0.254)
		(layers "F.Cu" "B.Cu")
		(net "IRQ_SML1_PMBUS_ALERT_N")
	)
	(via
		(at 183.779668 -409.626308)
		(size 0.508)
		(drill 0.254)
		(layers "F.Cu" "B.Cu")
		(net "IRQ_SML1_PMBUS_ALERT_N")
	)
	(via
		(at 306.434236 -32.890968)
		(size 0.508)
		(drill 0.254)
		(layers "F.Cu" "B.Cu")
		(net "IRQ_SML1_PMBUS_ALERT_N")
	)
	(via
		(at 282.48102 -434.7464)
		(size 0.508)
		(drill 0.254)
		(layers "F.Cu" "B.Cu")
		(net "IRQ_SML1_PMBUS_ALERT_N")
	)
	(via
		(at 28.82646 -55.015384)
		(size 0.508)
		(drill 0.254)
		(layers "F.Cu" "B.Cu")
		(net "IRQ_SML1_PMBUS_ALERT_N")
	)
	(via
		(at 250.93168 -327.828148)
		(size 0.508)
		(drill 0.254)
		(layers "F.Cu" "B.Cu")
		(net "IRQ_SML1_PMBUS_ALERT_N")
	)
	(via
		(at 313.459622 -36.820348)
		(size 0.508)
		(drill 0.254)
		(layers "F.Cu" "B.Cu")
		(net "IRQ_SML1_PMBUS_ALERT_N")
	)
	(via
		(at 188.49086 -90.444828)
		(size 0.508)
		(drill 0.254)
		(layers "F.Cu" "B.Cu")
		(net "IRQ_SML1_PMBUS_ALERT_N")
	)
	(segment
		(start 183.779668 -409.626308)
		(end 183.779668 -409.016962)
		(width 0.12954)
		(layer "B.Cu")
		(net "IRQ_SML1_PMBUS_ALERT_N")
	)
	(segment
		(start 183.657748 -406.845262)
		(end 183.657748 -404.951692)
		(width 0.12954)
		(layer "B.Cu")
		(net "IRQ_SML1_PMBUS_ALERT_N")
	)
	(segment
		(start 312.714132 -34.717228)
		(end 305.902868 -34.717228)
		(width 0.12954)
		(layer "B.Cu")
		(net "IRQ_SML1_PMBUS_ALERT_N")
	)
	(segment
		(start 313.459622 -36.820348)
		(end 312.843672 -36.820348)
		(width 0.12954)
		(layer "B.Cu")
		(net "IRQ_SML1_PMBUS_ALERT_N")
	)
	(segment
		(start 312.843672 -36.820348)
		(end 312.843672 -35.804348)
		(width 0.12954)
		(layer "B.Cu")
		(net "IRQ_SML1_PMBUS_ALERT_N")
	)
	(segment
		(start 183.779668 -409.016962)
		(end 183.459628 -408.696922)
		(width 0.12954)
		(layer "B.Cu")
		(net "IRQ_SML1_PMBUS_ALERT_N")
	)
	(segment
		(start 312.843672 -35.804348)
		(end 312.843672 -34.846768)
		(width 0.12954)
		(layer "B.Cu")
		(net "IRQ_SML1_PMBUS_ALERT_N")
	)
	(segment
		(start 183.657748 -404.951692)
		(end 183.559958 -404.853902)
		(width 0.12954)
		(layer "B.Cu")
		(net "IRQ_SML1_PMBUS_ALERT_N")
	)
	(segment
		(start 183.459628 -407.043382)
		(end 183.657748 -406.845262)
		(width 0.12954)
		(layer "B.Cu")
		(net "IRQ_SML1_PMBUS_ALERT_N")
	)
	(segment
		(start 305.697128 -34.511488)
		(end 305.697128 -33.628076)
		(width 0.12954)
		(layer "B.Cu")
		(net "IRQ_SML1_PMBUS_ALERT_N")
	)
	(segment
		(start 312.843672 -34.846768)
		(end 312.714132 -34.717228)
		(width 0.12954)
		(layer "B.Cu")
		(net "IRQ_SML1_PMBUS_ALERT_N")
	)
	(segment
		(start 305.697128 -33.628076)
		(end 306.434236 -32.890968)
		(width 0.12954)
		(layer "B.Cu")
		(net "IRQ_SML1_PMBUS_ALERT_N")
	)
	(segment
		(start 183.459628 -408.696922)
		(end 183.459628 -407.043382)
		(width 0.12954)
		(layer "B.Cu")
		(net "IRQ_SML1_PMBUS_ALERT_N")
	)
	(segment
		(start 305.902868 -34.717228)
		(end 305.697128 -34.511488)
		(width 0.12954)
		(layer "B.Cu")
		(net "IRQ_SML1_PMBUS_ALERT_N")
	)
	(segment
		(start 183.264048 -397.205708)
		(end 183.53786 -397.47952)
		(width 0.127)
		(layer "In2.Cu")
		(net "IRQ_SML1_PMBUS_ALERT_N")
	)
	(segment
		(start 183.53786 -397.47952)
		(end 183.53786 -398.5895)
		(width 0.127)
		(layer "In2.Cu")
		(net "IRQ_SML1_PMBUS_ALERT_N")
	)
	(segment
		(start 242.90528 -335.854548)
		(end 242.90528 -354.438204)
		(width 0.127)
		(layer "In2.Cu")
		(net "IRQ_SML1_PMBUS_ALERT_N")
	)
	(segment
		(start 250.93168 -327.828148)
		(end 242.90528 -335.854548)
		(width 0.127)
		(layer "In2.Cu")
		(net "IRQ_SML1_PMBUS_ALERT_N")
	)
	(segment
		(start 183.53786 -398.5895)
		(end 183.264048 -398.863312)
		(width 0.127)
		(layer "In2.Cu")
		(net "IRQ_SML1_PMBUS_ALERT_N")
	)
	(segment
		(start 182.977028 -401.185126)
		(end 182.977028 -404.188422)
		(width 0.127)
		(layer "In2.Cu")
		(net "IRQ_SML1_PMBUS_ALERT_N")
	)
	(segment
		(start 183.657748 -404.869142)
		(end 183.657748 -406.16378)
		(width 0.127)
		(layer "In2.Cu")
		(net "IRQ_SML1_PMBUS_ALERT_N")
	)
	(segment
		(start 242.90528 -354.438204)
		(end 220.936566 -376.406918)
		(width 0.127)
		(layer "In2.Cu")
		(net "IRQ_SML1_PMBUS_ALERT_N")
	)
	(segment
		(start 182.977028 -404.188422)
		(end 183.657748 -404.869142)
		(width 0.127)
		(layer "In2.Cu")
		(net "IRQ_SML1_PMBUS_ALERT_N")
	)
	(segment
		(start 183.779668 -406.2857)
		(end 183.779668 -409.626308)
		(width 0.127)
		(layer "In2.Cu")
		(net "IRQ_SML1_PMBUS_ALERT_N")
	)
	(segment
		(start 183.264048 -398.863312)
		(end 183.264048 -400.898106)
		(width 0.127)
		(layer "In2.Cu")
		(net "IRQ_SML1_PMBUS_ALERT_N")
	)
	(segment
		(start 220.936566 -376.406918)
		(end 200.354184 -376.406918)
		(width 0.127)
		(layer "In2.Cu")
		(net "IRQ_SML1_PMBUS_ALERT_N")
	)
	(segment
		(start 183.264048 -393.497054)
		(end 183.264048 -397.205708)
		(width 0.127)
		(layer "In2.Cu")
		(net "IRQ_SML1_PMBUS_ALERT_N")
	)
	(segment
		(start 183.657748 -406.16378)
		(end 183.779668 -406.2857)
		(width 0.127)
		(layer "In2.Cu")
		(net "IRQ_SML1_PMBUS_ALERT_N")
	)
	(segment
		(start 200.354184 -376.406918)
		(end 183.264048 -393.497054)
		(width 0.127)
		(layer "In2.Cu")
		(net "IRQ_SML1_PMBUS_ALERT_N")
	)
	(segment
		(start 183.264048 -400.898106)
		(end 182.977028 -401.185126)
		(width 0.127)
		(layer "In2.Cu")
		(net "IRQ_SML1_PMBUS_ALERT_N")
	)
	(segment
		(start 190.780416 -97.344992)
		(end 190.780416 -114.464084)
		(width 0.127)
		(layer "In4.Cu")
		(net "IRQ_SML1_PMBUS_ALERT_N")
	)
	(segment
		(start 188.5188 -93.801946)
		(end 188.5188 -95.083376)
		(width 0.127)
		(layer "In4.Cu")
		(net "IRQ_SML1_PMBUS_ALERT_N")
	)
	(segment
		(start 188.49086 -90.444828)
		(end 187.8838 -91.051888)
		(width 0.127)
		(layer "In4.Cu")
		(net "IRQ_SML1_PMBUS_ALERT_N")
	)
	(segment
		(start 187.8838 -91.051888)
		(end 187.8838 -93.166946)
		(width 0.127)
		(layer "In4.Cu")
		(net "IRQ_SML1_PMBUS_ALERT_N")
	)
	(segment
		(start 193.12128 -116.804948)
		(end 194.39001 -116.804948)
		(width 0.127)
		(layer "In4.Cu")
		(net "IRQ_SML1_PMBUS_ALERT_N")
	)
	(segment
		(start 190.780416 -114.464084)
		(end 193.12128 -116.804948)
		(width 0.127)
		(layer "In4.Cu")
		(net "IRQ_SML1_PMBUS_ALERT_N")
	)
	(segment
		(start 188.5188 -95.083376)
		(end 190.780416 -97.344992)
		(width 0.127)
		(layer "In4.Cu")
		(net "IRQ_SML1_PMBUS_ALERT_N")
	)
	(segment
		(start 187.8838 -93.166946)
		(end 188.5188 -93.801946)
		(width 0.127)
		(layer "In4.Cu")
		(net "IRQ_SML1_PMBUS_ALERT_N")
	)
	(segment
		(start 282.48102 -434.7464)
		(end 281.04338 -433.30876)
		(width 0.127)
		(layer "In6.Cu")
		(net "IRQ_SML1_PMBUS_ALERT_N")
	)
	(segment
		(start 292.0619 -407.8605)
		(end 294.28948 -405.63292)
		(width 0.127)
		(layer "In6.Cu")
		(net "IRQ_SML1_PMBUS_ALERT_N")
	)
	(segment
		(start 281.04338 -433.30876)
		(end 281.04338 -418.71646)
		(width 0.127)
		(layer "In6.Cu")
		(net "IRQ_SML1_PMBUS_ALERT_N")
	)
	(segment
		(start 281.04338 -418.71646)
		(end 284.644592 -415.115248)
		(width 0.127)
		(layer "In6.Cu")
		(net "IRQ_SML1_PMBUS_ALERT_N")
	)
	(segment
		(start 297.7642 -396.38732)
		(end 297.7642 -393.12088)
		(width 0.127)
		(layer "In6.Cu")
		(net "IRQ_SML1_PMBUS_ALERT_N")
	)
	(segment
		(start 297.7642 -393.12088)
		(end 291.77742 -387.1341)
		(width 0.127)
		(layer "In6.Cu")
		(net "IRQ_SML1_PMBUS_ALERT_N")
	)
	(segment
		(start 284.644592 -413.6009)
		(end 288.775394 -409.470098)
		(width 0.127)
		(layer "In6.Cu")
		(net "IRQ_SML1_PMBUS_ALERT_N")
	)
	(segment
		(start 289.325558 -409.470098)
		(end 290.935156 -407.8605)
		(width 0.127)
		(layer "In6.Cu")
		(net "IRQ_SML1_PMBUS_ALERT_N")
	)
	(segment
		(start 284.644592 -415.115248)
		(end 284.644592 -413.6009)
		(width 0.127)
		(layer "In6.Cu")
		(net "IRQ_SML1_PMBUS_ALERT_N")
	)
	(segment
		(start 291.77742 -387.1341)
		(end 289.16122 -387.1341)
		(width 0.127)
		(layer "In6.Cu")
		(net "IRQ_SML1_PMBUS_ALERT_N")
	)
	(segment
		(start 290.935156 -407.8605)
		(end 292.0619 -407.8605)
		(width 0.127)
		(layer "In6.Cu")
		(net "IRQ_SML1_PMBUS_ALERT_N")
	)
	(segment
		(start 294.28948 -399.86204)
		(end 297.7642 -396.38732)
		(width 0.127)
		(layer "In6.Cu")
		(net "IRQ_SML1_PMBUS_ALERT_N")
	)
	(segment
		(start 294.28948 -405.63292)
		(end 294.28948 -399.86204)
		(width 0.127)
		(layer "In6.Cu")
		(net "IRQ_SML1_PMBUS_ALERT_N")
	)
	(segment
		(start 288.775394 -409.470098)
		(end 289.325558 -409.470098)
		(width 0.127)
		(layer "In6.Cu")
		(net "IRQ_SML1_PMBUS_ALERT_N")
	)
	(segment
		(start 250.29668 -326.608948)
		(end 250.29668 -201.219308)
		(width 0.127)
		(layer "In11.Cu")
		(net "IRQ_SML1_PMBUS_ALERT_N")
	)
	(segment
		(start 248.473214 -130.913886)
		(end 248.473214 -129.864866)
		(width 0.127)
		(layer "In11.Cu")
		(net "IRQ_SML1_PMBUS_ALERT_N")
	)
	(segment
		(start 251.173996 -133.614668)
		(end 248.473214 -130.913886)
		(width 0.127)
		(layer "In11.Cu")
		(net "IRQ_SML1_PMBUS_ALERT_N")
	)
	(segment
		(start 248.473214 -129.864866)
		(end 248.67362 -129.66446)
		(width 0.127)
		(layer "In11.Cu")
		(net "IRQ_SML1_PMBUS_ALERT_N")
	)
	(segment
		(start 248.67362 -122.044968)
		(end 241.2746 -114.645948)
		(width 0.127)
		(layer "In11.Cu")
		(net "IRQ_SML1_PMBUS_ALERT_N")
	)
	(segment
		(start 250.93168 -327.243948)
		(end 250.29668 -326.608948)
		(width 0.127)
		(layer "In11.Cu")
		(net "IRQ_SML1_PMBUS_ALERT_N")
	)
	(segment
		(start 241.2746 -114.645948)
		(end 215.68918 -114.645948)
		(width 0.127)
		(layer "In11.Cu")
		(net "IRQ_SML1_PMBUS_ALERT_N")
	)
	(segment
		(start 248.59996 -199.522588)
		(end 248.59996 -138.12901)
		(width 0.127)
		(layer "In11.Cu")
		(net "IRQ_SML1_PMBUS_ALERT_N")
	)
	(segment
		(start 250.93168 -327.828148)
		(end 250.93168 -327.243948)
		(width 0.127)
		(layer "In11.Cu")
		(net "IRQ_SML1_PMBUS_ALERT_N")
	)
	(segment
		(start 250.29668 -201.219308)
		(end 248.59996 -199.522588)
		(width 0.127)
		(layer "In11.Cu")
		(net "IRQ_SML1_PMBUS_ALERT_N")
	)
	(segment
		(start 248.67362 -129.66446)
		(end 248.67362 -122.044968)
		(width 0.127)
		(layer "In11.Cu")
		(net "IRQ_SML1_PMBUS_ALERT_N")
	)
	(segment
		(start 251.173996 -135.554974)
		(end 251.173996 -133.614668)
		(width 0.127)
		(layer "In11.Cu")
		(net "IRQ_SML1_PMBUS_ALERT_N")
	)
	(segment
		(start 215.24468 -114.201448)
		(end 213.26856 -114.201448)
		(width 0.127)
		(layer "In11.Cu")
		(net "IRQ_SML1_PMBUS_ALERT_N")
	)
	(segment
		(start 248.59996 -138.12901)
		(end 251.173996 -135.554974)
		(width 0.127)
		(layer "In11.Cu")
		(net "IRQ_SML1_PMBUS_ALERT_N")
	)
	(segment
		(start 215.68918 -114.645948)
		(end 215.24468 -114.201448)
		(width 0.127)
		(layer "In11.Cu")
		(net "IRQ_SML1_PMBUS_ALERT_N")
	)
	(segment
		(start 198.326502 -117.535452)
		(end 195.120514 -117.535452)
		(width 0.127)
		(layer "In13.Cu")
		(net "IRQ_SML1_PMBUS_ALERT_N")
	)
	(segment
		(start 201.98588 -90.5256)
		(end 201.85888 -90.6526)
		(width 0.127)
		(layer "In13.Cu")
		(net "IRQ_SML1_PMBUS_ALERT_N")
	)
	(segment
		(start 199.6694 -90.6526)
		(end 199.3265 -90.9955)
		(width 0.127)
		(layer "In13.Cu")
		(net "IRQ_SML1_PMBUS_ALERT_N")
	)
	(segment
		(start 194.2592 -110.145068)
		(end 198.35876 -110.145068)
		(width 0.127)
		(layer "In13.Cu")
		(net "IRQ_SML1_PMBUS_ALERT_N")
	)
	(segment
		(start 199.3265 -94.4245)
		(end 191.25184 -102.49916)
		(width 0.127)
		(layer "In13.Cu")
		(net "IRQ_SML1_PMBUS_ALERT_N")
	)
	(segment
		(start 191.25184 -107.137708)
		(end 194.2592 -110.145068)
		(width 0.127)
		(layer "In13.Cu")
		(net "IRQ_SML1_PMBUS_ALERT_N")
	)
	(segment
		(start 199.399398 -118.608348)
		(end 198.326502 -117.535452)
		(width 0.127)
		(layer "In13.Cu")
		(net "IRQ_SML1_PMBUS_ALERT_N")
	)
	(segment
		(start 200.96988 -118.176548)
		(end 200.53808 -118.608348)
		(width 0.127)
		(layer "In13.Cu")
		(net "IRQ_SML1_PMBUS_ALERT_N")
	)
	(segment
		(start 201.98588 -90.134948)
		(end 201.98588 -90.5256)
		(width 0.127)
		(layer "In13.Cu")
		(net "IRQ_SML1_PMBUS_ALERT_N")
	)
	(segment
		(start 195.120514 -117.535452)
		(end 194.39001 -116.804948)
		(width 0.127)
		(layer "In13.Cu")
		(net "IRQ_SML1_PMBUS_ALERT_N")
	)
	(segment
		(start 200.53808 -118.608348)
		(end 199.399398 -118.608348)
		(width 0.127)
		(layer "In13.Cu")
		(net "IRQ_SML1_PMBUS_ALERT_N")
	)
	(segment
		(start 200.96988 -111.369348)
		(end 200.96988 -118.176548)
		(width 0.127)
		(layer "In13.Cu")
		(net "IRQ_SML1_PMBUS_ALERT_N")
	)
	(segment
		(start 198.35876 -110.145068)
		(end 198.98868 -110.774988)
		(width 0.127)
		(layer "In13.Cu")
		(net "IRQ_SML1_PMBUS_ALERT_N")
	)
	(segment
		(start 201.85888 -90.6526)
		(end 199.6694 -90.6526)
		(width 0.127)
		(layer "In13.Cu")
		(net "IRQ_SML1_PMBUS_ALERT_N")
	)
	(segment
		(start 198.98868 -110.774988)
		(end 200.37552 -110.774988)
		(width 0.127)
		(layer "In13.Cu")
		(net "IRQ_SML1_PMBUS_ALERT_N")
	)
	(segment
		(start 200.37552 -110.774988)
		(end 200.96988 -111.369348)
		(width 0.127)
		(layer "In13.Cu")
		(net "IRQ_SML1_PMBUS_ALERT_N")
	)
	(segment
		(start 191.25184 -102.49916)
		(end 191.25184 -107.137708)
		(width 0.127)
		(layer "In13.Cu")
		(net "IRQ_SML1_PMBUS_ALERT_N")
	)
	(segment
		(start 199.3265 -90.9955)
		(end 199.3265 -94.4245)
		(width 0.127)
		(layer "In13.Cu")
		(net "IRQ_SML1_PMBUS_ALERT_N")
	)
	(segment
		(start 201.68616 -82.997548)
		(end 222.99676 -82.997548)
		(width 0.127)
		(layer "In15.Cu")
		(net "IRQ_SML1_PMBUS_ALERT_N")
	)
	(segment
		(start 296.91838 -40.034464)
		(end 296.91838 -38.633654)
		(width 0.127)
		(layer "In15.Cu")
		(net "IRQ_SML1_PMBUS_ALERT_N")
	)
	(segment
		(start 182.77332 -411.66542)
		(end 183.37022 -411.06852)
		(width 0.127)
		(layer "In15.Cu")
		(net "IRQ_SML1_PMBUS_ALERT_N")
	)
	(segment
		(start 30.316424 -56.505348)
		(end 46.05274 -56.505348)
		(width 0.127)
		(layer "In15.Cu")
		(net "IRQ_SML1_PMBUS_ALERT_N")
	)
	(segment
		(start 222.99676 -82.997548)
		(end 234.50296 -71.491348)
		(width 0.127)
		(layer "In15.Cu")
		(net "IRQ_SML1_PMBUS_ALERT_N")
	)
	(segment
		(start 244.171216 -71.491348)
		(end 246.193056 -69.469508)
		(width 0.127)
		(layer "In15.Cu")
		(net "IRQ_SML1_PMBUS_ALERT_N")
	)
	(segment
		(start 196.26072 -426.06976)
		(end 182.77332 -412.58236)
		(width 0.127)
		(layer "In15.Cu")
		(net "IRQ_SML1_PMBUS_ALERT_N")
	)
	(segment
		(start 187.67552 -91.260168)
		(end 188.49086 -90.444828)
		(width 0.127)
		(layer "In15.Cu")
		(net "IRQ_SML1_PMBUS_ALERT_N")
	)
	(segment
		(start 168.80078 -91.260168)
		(end 170.652948 -89.408)
		(width 0.127)
		(layer "In15.Cu")
		(net "IRQ_SML1_PMBUS_ALERT_N")
	)
	(segment
		(start 213.26856 -114.201448)
		(end 212.255608 -115.2144)
		(width 0.127)
		(layer "In15.Cu")
		(net "IRQ_SML1_PMBUS_ALERT_N")
	)
	(segment
		(start 292.25748 -48.179228)
		(end 292.25748 -44.695364)
		(width 0.127)
		(layer "In15.Cu")
		(net "IRQ_SML1_PMBUS_ALERT_N")
	)
	(segment
		(start 65.64376 -87.521288)
		(end 110.06074 -87.521288)
		(width 0.127)
		(layer "In15.Cu")
		(net "IRQ_SML1_PMBUS_ALERT_N")
	)
	(segment
		(start 280.49728 -439.15584)
		(end 278.20366 -439.15584)
		(width 0.127)
		(layer "In15.Cu")
		(net "IRQ_SML1_PMBUS_ALERT_N")
	)
	(segment
		(start 122.95886 -81.938368)
		(end 127.3048 -81.938368)
		(width 0.127)
		(layer "In15.Cu")
		(net "IRQ_SML1_PMBUS_ALERT_N")
	)
	(segment
		(start 296.91838 -38.633654)
		(end 302.661066 -32.890968)
		(width 0.127)
		(layer "In15.Cu")
		(net "IRQ_SML1_PMBUS_ALERT_N")
	)
	(segment
		(start 281.943556 -434.7464)
		(end 281.067002 -435.622954)
		(width 0.127)
		(layer "In15.Cu")
		(net "IRQ_SML1_PMBUS_ALERT_N")
	)
	(segment
		(start 198.57212 -116.246148)
		(end 194.94881 -116.246148)
		(width 0.127)
		(layer "In15.Cu")
		(net "IRQ_SML1_PMBUS_ALERT_N")
	)
	(segment
		(start 276.94382 -437.896)
		(end 198.2851 -437.896)
		(width 0.127)
		(layer "In15.Cu")
		(net "IRQ_SML1_PMBUS_ALERT_N")
	)
	(segment
		(start 129.487168 -79.756)
		(end 145.5928 -79.756)
		(width 0.127)
		(layer "In15.Cu")
		(net "IRQ_SML1_PMBUS_ALERT_N")
	)
	(segment
		(start 183.37022 -411.06852)
		(end 183.37022 -410.035756)
		(width 0.127)
		(layer "In15.Cu")
		(net "IRQ_SML1_PMBUS_ALERT_N")
	)
	(segment
		(start 194.94881 -116.246148)
		(end 194.39001 -116.804948)
		(width 0.127)
		(layer "In15.Cu")
		(net "IRQ_SML1_PMBUS_ALERT_N")
	)
	(segment
		(start 275.14296 -65.293748)
		(end 292.25748 -48.179228)
		(width 0.127)
		(layer "In15.Cu")
		(net "IRQ_SML1_PMBUS_ALERT_N")
	)
	(segment
		(start 302.661066 -32.890968)
		(end 306.434236 -32.890968)
		(width 0.127)
		(layer "In15.Cu")
		(net "IRQ_SML1_PMBUS_ALERT_N")
	)
	(segment
		(start 212.255608 -115.2144)
		(end 207.1624 -115.2144)
		(width 0.127)
		(layer "In15.Cu")
		(net "IRQ_SML1_PMBUS_ALERT_N")
	)
	(segment
		(start 113.72088 -83.861148)
		(end 121.03608 -83.861148)
		(width 0.127)
		(layer "In15.Cu")
		(net "IRQ_SML1_PMBUS_ALERT_N")
	)
	(segment
		(start 262.281416 -65.293748)
		(end 275.14296 -65.293748)
		(width 0.127)
		(layer "In15.Cu")
		(net "IRQ_SML1_PMBUS_ALERT_N")
	)
	(segment
		(start 201.32548 -88.572848)
		(end 201.32548 -83.358228)
		(width 0.127)
		(layer "In15.Cu")
		(net "IRQ_SML1_PMBUS_ALERT_N")
	)
	(segment
		(start 147.4978 -81.661)
		(end 147.4978 -82.6516)
		(width 0.127)
		(layer "In15.Cu")
		(net "IRQ_SML1_PMBUS_ALERT_N")
	)
	(segment
		(start 282.48102 -434.7464)
		(end 281.943556 -434.7464)
		(width 0.127)
		(layer "In15.Cu")
		(net "IRQ_SML1_PMBUS_ALERT_N")
	)
	(segment
		(start 281.067002 -438.586118)
		(end 280.49728 -439.15584)
		(width 0.127)
		(layer "In15.Cu")
		(net "IRQ_SML1_PMBUS_ALERT_N")
	)
	(segment
		(start 281.067002 -435.622954)
		(end 281.067002 -438.586118)
		(width 0.127)
		(layer "In15.Cu")
		(net "IRQ_SML1_PMBUS_ALERT_N")
	)
	(segment
		(start 46.05274 -56.505348)
		(end 53.0987 -63.551308)
		(width 0.127)
		(layer "In15.Cu")
		(net "IRQ_SML1_PMBUS_ALERT_N")
	)
	(segment
		(start 147.4978 -82.6516)
		(end 149.5806 -84.7344)
		(width 0.127)
		(layer "In15.Cu")
		(net "IRQ_SML1_PMBUS_ALERT_N")
	)
	(segment
		(start 182.77332 -412.58236)
		(end 182.77332 -411.66542)
		(width 0.127)
		(layer "In15.Cu")
		(net "IRQ_SML1_PMBUS_ALERT_N")
	)
	(segment
		(start 184.51068 -91.260168)
		(end 187.67552 -91.260168)
		(width 0.127)
		(layer "In15.Cu")
		(net "IRQ_SML1_PMBUS_ALERT_N")
	)
	(segment
		(start 292.25748 -44.695364)
		(end 296.91838 -40.034464)
		(width 0.127)
		(layer "In15.Cu")
		(net "IRQ_SML1_PMBUS_ALERT_N")
	)
	(segment
		(start 251.1806 -69.469508)
		(end 253.63678 -67.013328)
		(width 0.127)
		(layer "In15.Cu")
		(net "IRQ_SML1_PMBUS_ALERT_N")
	)
	(segment
		(start 196.26072 -435.87162)
		(end 196.26072 -426.06976)
		(width 0.127)
		(layer "In15.Cu")
		(net "IRQ_SML1_PMBUS_ALERT_N")
	)
	(segment
		(start 201.98588 -90.134948)
		(end 201.98588 -89.233248)
		(width 0.127)
		(layer "In15.Cu")
		(net "IRQ_SML1_PMBUS_ALERT_N")
	)
	(segment
		(start 149.5806 -84.7344)
		(end 150.0886 -84.7344)
		(width 0.127)
		(layer "In15.Cu")
		(net "IRQ_SML1_PMBUS_ALERT_N")
	)
	(segment
		(start 110.06074 -87.521288)
		(end 113.72088 -83.861148)
		(width 0.127)
		(layer "In15.Cu")
		(net "IRQ_SML1_PMBUS_ALERT_N")
	)
	(segment
		(start 246.193056 -69.469508)
		(end 251.1806 -69.469508)
		(width 0.127)
		(layer "In15.Cu")
		(net "IRQ_SML1_PMBUS_ALERT_N")
	)
	(segment
		(start 253.63678 -67.013328)
		(end 262.281416 -65.293748)
		(width 0.127)
		(layer "In15.Cu")
		(net "IRQ_SML1_PMBUS_ALERT_N")
	)
	(segment
		(start 156.614368 -91.260168)
		(end 168.80078 -91.260168)
		(width 0.127)
		(layer "In15.Cu")
		(net "IRQ_SML1_PMBUS_ALERT_N")
	)
	(segment
		(start 201.32548 -83.358228)
		(end 201.68616 -82.997548)
		(width 0.127)
		(layer "In15.Cu")
		(net "IRQ_SML1_PMBUS_ALERT_N")
	)
	(segment
		(start 201.98588 -89.233248)
		(end 201.32548 -88.572848)
		(width 0.127)
		(layer "In15.Cu")
		(net "IRQ_SML1_PMBUS_ALERT_N")
	)
	(segment
		(start 127.3048 -81.938368)
		(end 129.487168 -79.756)
		(width 0.127)
		(layer "In15.Cu")
		(net "IRQ_SML1_PMBUS_ALERT_N")
	)
	(segment
		(start 198.2851 -437.896)
		(end 196.26072 -435.87162)
		(width 0.127)
		(layer "In15.Cu")
		(net "IRQ_SML1_PMBUS_ALERT_N")
	)
	(segment
		(start 121.03608 -83.861148)
		(end 122.95886 -81.938368)
		(width 0.127)
		(layer "In15.Cu")
		(net "IRQ_SML1_PMBUS_ALERT_N")
	)
	(segment
		(start 170.652948 -89.408)
		(end 182.658512 -89.408)
		(width 0.127)
		(layer "In15.Cu")
		(net "IRQ_SML1_PMBUS_ALERT_N")
	)
	(segment
		(start 278.20366 -439.15584)
		(end 276.94382 -437.896)
		(width 0.127)
		(layer "In15.Cu")
		(net "IRQ_SML1_PMBUS_ALERT_N")
	)
	(segment
		(start 200.07834 -114.739928)
		(end 198.57212 -116.246148)
		(width 0.127)
		(layer "In15.Cu")
		(net "IRQ_SML1_PMBUS_ALERT_N")
	)
	(segment
		(start 53.0987 -74.976228)
		(end 65.64376 -87.521288)
		(width 0.127)
		(layer "In15.Cu")
		(net "IRQ_SML1_PMBUS_ALERT_N")
	)
	(segment
		(start 206.687928 -114.739928)
		(end 200.07834 -114.739928)
		(width 0.127)
		(layer "In15.Cu")
		(net "IRQ_SML1_PMBUS_ALERT_N")
	)
	(segment
		(start 150.0886 -84.7344)
		(end 156.614368 -91.260168)
		(width 0.127)
		(layer "In15.Cu")
		(net "IRQ_SML1_PMBUS_ALERT_N")
	)
	(segment
		(start 183.37022 -410.035756)
		(end 183.779668 -409.626308)
		(width 0.127)
		(layer "In15.Cu")
		(net "IRQ_SML1_PMBUS_ALERT_N")
	)
	(segment
		(start 207.1624 -115.2144)
		(end 206.687928 -114.739928)
		(width 0.127)
		(layer "In15.Cu")
		(net "IRQ_SML1_PMBUS_ALERT_N")
	)
	(segment
		(start 53.0987 -63.551308)
		(end 53.0987 -74.976228)
		(width 0.127)
		(layer "In15.Cu")
		(net "IRQ_SML1_PMBUS_ALERT_N")
	)
	(segment
		(start 182.658512 -89.408)
		(end 184.51068 -91.260168)
		(width 0.127)
		(layer "In15.Cu")
		(net "IRQ_SML1_PMBUS_ALERT_N")
	)
	(segment
		(start 234.50296 -71.491348)
		(end 244.171216 -71.491348)
		(width 0.127)
		(layer "In15.Cu")
		(net "IRQ_SML1_PMBUS_ALERT_N")
	)
	(segment
		(start 28.82646 -55.015384)
		(end 30.316424 -56.505348)
		(width 0.127)
		(layer "In15.Cu")
		(net "IRQ_SML1_PMBUS_ALERT_N")
	)
	(segment
		(start 145.5928 -79.756)
		(end 147.4978 -81.661)
		(width 0.127)
		(layer "In15.Cu")
		(net "IRQ_SML1_PMBUS_ALERT_N")
	)
	(segment
		(start 28.194 -58.960512)
		(end 28.8036 -58.960512)
		(width 0.12954)
		(layer "F.Cu")
		(net "IRQ_SML0_ALERT_R_N")
	)
	(segment
		(start 309.122572 -33.772348)
		(end 306.352956 -33.772348)
		(width 0.12954)
		(layer "F.Cu")
		(net "IRQ_SML0_ALERT_R_N")
	)
	(segment
		(start 170.955716 -110.575344)
		(end 170.555666 -110.975394)
		(width 0.12954)
		(layer "F.Cu")
		(net "IRQ_SML0_ALERT_R_N")
	)
	(via
		(at 114.15268 -107.737148)
		(size 0.508)
		(drill 0.254)
		(layers "F.Cu" "B.Cu")
		(net "IRQ_SML0_ALERT_R_N")
	)
	(via
		(at 28.8036 -58.960512)
		(size 0.508)
		(drill 0.254)
		(layers "F.Cu" "B.Cu")
		(net "IRQ_SML0_ALERT_R_N")
	)
	(via
		(at 306.352956 -33.772348)
		(size 0.508)
		(drill 0.254)
		(layers "F.Cu" "B.Cu")
		(net "IRQ_SML0_ALERT_R_N")
	)
	(via
		(at 170.555666 -110.975394)
		(size 0.4572)
		(drill 0.254)
		(layers "F.Cu" "B.Cu")
		(net "IRQ_SML0_ALERT_R_N")
	)
	(via
		(at 109.82452 -88.016588)
		(size 0.508)
		(drill 0.254)
		(layers "F.Cu" "B.Cu")
		(net "IRQ_SML0_ALERT_R_N")
	)
	(segment
		(start 111.8362 -107.737148)
		(end 111.15548 -107.056428)
		(width 0.127)
		(layer "In2.Cu")
		(net "IRQ_SML0_ALERT_R_N")
	)
	(segment
		(start 111.15548 -89.347548)
		(end 109.82452 -88.016588)
		(width 0.127)
		(layer "In2.Cu")
		(net "IRQ_SML0_ALERT_R_N")
	)
	(segment
		(start 111.15548 -107.056428)
		(end 111.15548 -89.347548)
		(width 0.127)
		(layer "In2.Cu")
		(net "IRQ_SML0_ALERT_R_N")
	)
	(segment
		(start 114.15268 -107.737148)
		(end 111.8362 -107.737148)
		(width 0.127)
		(layer "In2.Cu")
		(net "IRQ_SML0_ALERT_R_N")
	)
	(segment
		(start 222.399352 -88.156034)
		(end 238.653828 -88.156034)
		(width 0.127)
		(layer "In13.Cu")
		(net "IRQ_SML0_ALERT_R_N")
	)
	(segment
		(start 304.7365 -37.589968)
		(end 304.7365 -35.388804)
		(width 0.127)
		(layer "In13.Cu")
		(net "IRQ_SML0_ALERT_R_N")
	)
	(segment
		(start 169.87774 -91.656154)
		(end 171.212256 -90.321638)
		(width 0.127)
		(layer "In13.Cu")
		(net "IRQ_SML0_ALERT_R_N")
	)
	(segment
		(start 285.04388 -74.677778)
		(end 285.04388 -60.08497)
		(width 0.127)
		(layer "In13.Cu")
		(net "IRQ_SML0_ALERT_R_N")
	)
	(segment
		(start 170.1292 -108.115608)
		(end 169.32148 -107.307888)
		(width 0.127)
		(layer "In13.Cu")
		(net "IRQ_SML0_ALERT_R_N")
	)
	(segment
		(start 290.816284 -51.271932)
		(end 290.816284 -48.960024)
		(width 0.127)
		(layer "In13.Cu")
		(net "IRQ_SML0_ALERT_R_N")
	)
	(segment
		(start 287.833308 -54.254908)
		(end 290.816284 -51.271932)
		(width 0.127)
		(layer "In13.Cu")
		(net "IRQ_SML0_ALERT_R_N")
	)
	(segment
		(start 169.87774 -99.591368)
		(end 169.87774 -91.656154)
		(width 0.127)
		(layer "In13.Cu")
		(net "IRQ_SML0_ALERT_R_N")
	)
	(segment
		(start 170.555666 -110.975394)
		(end 170.555666 -110.045754)
		(width 0.127)
		(layer "In13.Cu")
		(net "IRQ_SML0_ALERT_R_N")
	)
	(segment
		(start 176.183544 -90.321638)
		(end 181.696614 -84.808568)
		(width 0.127)
		(layer "In13.Cu")
		(net "IRQ_SML0_ALERT_R_N")
	)
	(segment
		(start 169.32148 -100.147628)
		(end 169.87774 -99.591368)
		(width 0.127)
		(layer "In13.Cu")
		(net "IRQ_SML0_ALERT_R_N")
	)
	(segment
		(start 300.3677 -41.958768)
		(end 304.7365 -37.589968)
		(width 0.127)
		(layer "In13.Cu")
		(net "IRQ_SML0_ALERT_R_N")
	)
	(segment
		(start 287.833308 -57.295542)
		(end 287.833308 -54.254908)
		(width 0.127)
		(layer "In13.Cu")
		(net "IRQ_SML0_ALERT_R_N")
	)
	(segment
		(start 297.81754 -41.958768)
		(end 300.3677 -41.958768)
		(width 0.127)
		(layer "In13.Cu")
		(net "IRQ_SML0_ALERT_R_N")
	)
	(segment
		(start 304.7365 -35.388804)
		(end 306.352956 -33.772348)
		(width 0.127)
		(layer "In13.Cu")
		(net "IRQ_SML0_ALERT_R_N")
	)
	(segment
		(start 285.04388 -60.08497)
		(end 287.833308 -57.295542)
		(width 0.127)
		(layer "In13.Cu")
		(net "IRQ_SML0_ALERT_R_N")
	)
	(segment
		(start 171.212256 -90.321638)
		(end 176.183544 -90.321638)
		(width 0.127)
		(layer "In13.Cu")
		(net "IRQ_SML0_ALERT_R_N")
	)
	(segment
		(start 170.1292 -109.619288)
		(end 170.1292 -108.115608)
		(width 0.127)
		(layer "In13.Cu")
		(net "IRQ_SML0_ALERT_R_N")
	)
	(segment
		(start 244.126512 -82.68335)
		(end 277.038308 -82.68335)
		(width 0.127)
		(layer "In13.Cu")
		(net "IRQ_SML0_ALERT_R_N")
	)
	(segment
		(start 238.653828 -88.156034)
		(end 244.126512 -82.68335)
		(width 0.127)
		(layer "In13.Cu")
		(net "IRQ_SML0_ALERT_R_N")
	)
	(segment
		(start 169.32148 -107.307888)
		(end 169.32148 -100.147628)
		(width 0.127)
		(layer "In13.Cu")
		(net "IRQ_SML0_ALERT_R_N")
	)
	(segment
		(start 277.038308 -82.68335)
		(end 285.04388 -74.677778)
		(width 0.127)
		(layer "In13.Cu")
		(net "IRQ_SML0_ALERT_R_N")
	)
	(segment
		(start 181.696614 -84.808568)
		(end 219.051886 -84.808568)
		(width 0.127)
		(layer "In13.Cu")
		(net "IRQ_SML0_ALERT_R_N")
	)
	(segment
		(start 219.051886 -84.808568)
		(end 222.399352 -88.156034)
		(width 0.127)
		(layer "In13.Cu")
		(net "IRQ_SML0_ALERT_R_N")
	)
	(segment
		(start 290.816284 -48.960024)
		(end 297.81754 -41.958768)
		(width 0.127)
		(layer "In13.Cu")
		(net "IRQ_SML0_ALERT_R_N")
	)
	(segment
		(start 170.555666 -110.045754)
		(end 170.1292 -109.619288)
		(width 0.127)
		(layer "In13.Cu")
		(net "IRQ_SML0_ALERT_R_N")
	)
	(segment
		(start 146.02714 -108.334302)
		(end 129.649474 -108.334302)
		(width 0.127)
		(layer "In15.Cu")
		(net "IRQ_SML0_ALERT_R_N")
	)
	(segment
		(start 116.04752 -109.631988)
		(end 114.15268 -107.737148)
		(width 0.127)
		(layer "In15.Cu")
		(net "IRQ_SML0_ALERT_R_N")
	)
	(segment
		(start 28.8036 -58.960512)
		(end 29.754322 -58.00979)
		(width 0.127)
		(layer "In15.Cu")
		(net "IRQ_SML0_ALERT_R_N")
	)
	(segment
		(start 154.140408 -112.169448)
		(end 149.862286 -112.169448)
		(width 0.127)
		(layer "In15.Cu")
		(net "IRQ_SML0_ALERT_R_N")
	)
	(segment
		(start 126.95428 -106.873548)
		(end 124.19584 -109.631988)
		(width 0.127)
		(layer "In15.Cu")
		(net "IRQ_SML0_ALERT_R_N")
	)
	(segment
		(start 52.57038 -63.668148)
		(end 52.57038 -75.141328)
		(width 0.127)
		(layer "In15.Cu")
		(net "IRQ_SML0_ALERT_R_N")
	)
	(segment
		(start 164.97554 -113.109248)
		(end 155.080208 -113.109248)
		(width 0.127)
		(layer "In15.Cu")
		(net "IRQ_SML0_ALERT_R_N")
	)
	(segment
		(start 124.19584 -109.631988)
		(end 116.04752 -109.631988)
		(width 0.127)
		(layer "In15.Cu")
		(net "IRQ_SML0_ALERT_R_N")
	)
	(segment
		(start 169.073322 -112.101884)
		(end 165.982904 -112.101884)
		(width 0.127)
		(layer "In15.Cu")
		(net "IRQ_SML0_ALERT_R_N")
	)
	(segment
		(start 169.401236 -111.77397)
		(end 169.073322 -112.101884)
		(width 0.127)
		(layer "In15.Cu")
		(net "IRQ_SML0_ALERT_R_N")
	)
	(segment
		(start 128.18872 -106.873548)
		(end 126.95428 -106.873548)
		(width 0.127)
		(layer "In15.Cu")
		(net "IRQ_SML0_ALERT_R_N")
	)
	(segment
		(start 129.649474 -108.334302)
		(end 128.18872 -106.873548)
		(width 0.127)
		(layer "In15.Cu")
		(net "IRQ_SML0_ALERT_R_N")
	)
	(segment
		(start 52.57038 -75.141328)
		(end 65.44564 -88.016588)
		(width 0.127)
		(layer "In15.Cu")
		(net "IRQ_SML0_ALERT_R_N")
	)
	(segment
		(start 149.862286 -112.169448)
		(end 146.02714 -108.334302)
		(width 0.127)
		(layer "In15.Cu")
		(net "IRQ_SML0_ALERT_R_N")
	)
	(segment
		(start 165.982904 -112.101884)
		(end 164.97554 -113.109248)
		(width 0.127)
		(layer "In15.Cu")
		(net "IRQ_SML0_ALERT_R_N")
	)
	(segment
		(start 170.555666 -110.975394)
		(end 170.555666 -111.532162)
		(width 0.127)
		(layer "In15.Cu")
		(net "IRQ_SML0_ALERT_R_N")
	)
	(segment
		(start 170.313858 -111.77397)
		(end 169.401236 -111.77397)
		(width 0.127)
		(layer "In15.Cu")
		(net "IRQ_SML0_ALERT_R_N")
	)
	(segment
		(start 46.912022 -58.00979)
		(end 52.57038 -63.668148)
		(width 0.127)
		(layer "In15.Cu")
		(net "IRQ_SML0_ALERT_R_N")
	)
	(segment
		(start 155.080208 -113.109248)
		(end 154.140408 -112.169448)
		(width 0.127)
		(layer "In15.Cu")
		(net "IRQ_SML0_ALERT_R_N")
	)
	(segment
		(start 170.555666 -111.532162)
		(end 170.313858 -111.77397)
		(width 0.127)
		(layer "In15.Cu")
		(net "IRQ_SML0_ALERT_R_N")
	)
	(segment
		(start 65.44564 -88.016588)
		(end 109.82452 -88.016588)
		(width 0.127)
		(layer "In15.Cu")
		(net "IRQ_SML0_ALERT_R_N")
	)
	(segment
		(start 29.754322 -58.00979)
		(end 46.912022 -58.00979)
		(width 0.127)
		(layer "In15.Cu")
		(net "IRQ_SML0_ALERT_R_N")
	)
	(segment
		(start 314.489592 -35.23107)
		(end 314.86221 -35.603688)
		(width 0.12954)
		(layer "F.Cu")
		(net "IRQ_SML0_ALERT_N")
	)
	(segment
		(start 323.440806 -41.02354)
		(end 324.86473 -42.447464)
		(width 0.0889)
		(layer "F.Cu")
		(net "IRQ_SML0_ALERT_N")
	)
	(segment
		(start 322.56095 -40.180768)
		(end 322.56095 -40.544242)
		(width 0.0889)
		(layer "F.Cu")
		(net "IRQ_SML0_ALERT_N")
	)
	(segment
		(start 322.56095 -40.544242)
		(end 323.040248 -41.02354)
		(width 0.0889)
		(layer "F.Cu")
		(net "IRQ_SML0_ALERT_N")
	)
	(segment
		(start 323.040248 -41.02354)
		(end 323.440806 -41.02354)
		(width 0.0889)
		(layer "F.Cu")
		(net "IRQ_SML0_ALERT_N")
	)
	(segment
		(start 320.839338 -39.022528)
		(end 321.791076 -39.022528)
		(width 0.12954)
		(layer "F.Cu")
		(net "IRQ_SML0_ALERT_N")
	)
	(segment
		(start 312.843672 -34.102548)
		(end 313.198256 -34.102548)
		(width 0.12954)
		(layer "F.Cu")
		(net "IRQ_SML0_ALERT_N")
	)
	(segment
		(start 321.791076 -39.022528)
		(end 322.56095 -39.792402)
		(width 0.12954)
		(layer "F.Cu")
		(net "IRQ_SML0_ALERT_N")
	)
	(segment
		(start 314.86221 -35.603688)
		(end 316.571122 -35.603688)
		(width 0.12954)
		(layer "F.Cu")
		(net "IRQ_SML0_ALERT_N")
	)
	(segment
		(start 309.922672 -33.772348)
		(end 310.956452 -33.772348)
		(width 0.12954)
		(layer "F.Cu")
		(net "IRQ_SML0_ALERT_N")
	)
	(segment
		(start 310.956452 -33.772348)
		(end 311.230772 -33.498028)
		(width 0.12954)
		(layer "F.Cu")
		(net "IRQ_SML0_ALERT_N")
	)
	(segment
		(start 313.198256 -34.102548)
		(end 313.320176 -33.980628)
		(width 0.12954)
		(layer "F.Cu")
		(net "IRQ_SML0_ALERT_N")
	)
	(segment
		(start 316.571122 -35.603688)
		(end 318.448182 -37.480748)
		(width 0.12954)
		(layer "F.Cu")
		(net "IRQ_SML0_ALERT_N")
	)
	(segment
		(start 318.448182 -37.480748)
		(end 319.297558 -37.480748)
		(width 0.12954)
		(layer "F.Cu")
		(net "IRQ_SML0_ALERT_N")
	)
	(segment
		(start 319.297558 -37.480748)
		(end 320.839338 -39.022528)
		(width 0.12954)
		(layer "F.Cu")
		(net "IRQ_SML0_ALERT_N")
	)
	(segment
		(start 312.714132 -33.498028)
		(end 312.843672 -33.627568)
		(width 0.12954)
		(layer "F.Cu")
		(net "IRQ_SML0_ALERT_N")
	)
	(segment
		(start 324.86473 -42.447464)
		(end 326.999854 -42.447464)
		(width 0.0889)
		(layer "F.Cu")
		(net "IRQ_SML0_ALERT_N")
	)
	(segment
		(start 313.849258 -33.980628)
		(end 314.191396 -34.322766)
		(width 0.12954)
		(layer "F.Cu")
		(net "IRQ_SML0_ALERT_N")
	)
	(segment
		(start 314.191396 -34.932874)
		(end 314.489592 -35.23107)
		(width 0.12954)
		(layer "F.Cu")
		(net "IRQ_SML0_ALERT_N")
	)
	(segment
		(start 312.843672 -33.627568)
		(end 312.843672 -34.102548)
		(width 0.12954)
		(layer "F.Cu")
		(net "IRQ_SML0_ALERT_N")
	)
	(segment
		(start 311.230772 -33.498028)
		(end 312.714132 -33.498028)
		(width 0.12954)
		(layer "F.Cu")
		(net "IRQ_SML0_ALERT_N")
	)
	(segment
		(start 314.191396 -34.322766)
		(end 314.191396 -34.932874)
		(width 0.12954)
		(layer "F.Cu")
		(net "IRQ_SML0_ALERT_N")
	)
	(segment
		(start 313.320176 -33.980628)
		(end 313.849258 -33.980628)
		(width 0.12954)
		(layer "F.Cu")
		(net "IRQ_SML0_ALERT_N")
	)
	(segment
		(start 322.56095 -39.792402)
		(end 322.56095 -40.180768)
		(width 0.12954)
		(layer "F.Cu")
		(net "IRQ_SML0_ALERT_N")
	)
	(via
		(at 314.489592 -35.23107)
		(size 0.762)
		(drill 0.381)
		(layers "F.Cu" "B.Cu")
		(net "IRQ_SML0_ALERT_N")
	)
	(segment
		(start 334.864456 -41.871646)
		(end 334.325468 -41.871646)
		(width 0.12954)
		(layer "F.Cu")
		(net "IRQ_SMI_ACTIVE_N")
	)
	(via
		(at 342.412066 -32.886396)
		(size 0.6604)
		(drill 0.3302)
		(layers "F.Cu" "B.Cu")
		(net "IRQ_SMI_ACTIVE_N")
	)
	(via
		(at 334.325468 -41.871646)
		(size 0.4572)
		(drill 0.2032)
		(layers "F.Cu" "B.Cu")
		(net "IRQ_SMI_ACTIVE_N")
	)
	(segment
		(start 335.924398 -40.366696)
		(end 335.973166 -40.366696)
		(width 0.0889)
		(layer "B.Cu")
		(net "IRQ_SMI_ACTIVE_N")
	)
	(segment
		(start 342.412066 -32.886396)
		(end 343.157556 -32.140906)
		(width 0.12954)
		(layer "B.Cu")
		(net "IRQ_SMI_ACTIVE_N")
	)
	(segment
		(start 336.278728 -40.179244)
		(end 336.374994 -40.012112)
		(width 0.0889)
		(layer "B.Cu")
		(net "IRQ_SMI_ACTIVE_N")
	)
	(segment
		(start 343.157556 -32.140906)
		(end 343.157556 -31.882842)
		(width 0.12954)
		(layer "B.Cu")
		(net "IRQ_SMI_ACTIVE_N")
	)
	(segment
		(start 334.325468 -41.871646)
		(end 334.325468 -42.18432)
		(width 0.0889)
		(layer "B.Cu")
		(net "IRQ_SMI_ACTIVE_N")
	)
	(segment
		(start 336.374994 -40.012112)
		(end 336.374994 -39.805864)
		(width 0.0889)
		(layer "B.Cu")
		(net "IRQ_SMI_ACTIVE_N")
	)
	(segment
		(start 336.374994 -39.805864)
		(end 336.595466 -39.585392)
		(width 0.0889)
		(layer "B.Cu")
		(net "IRQ_SMI_ACTIVE_N")
	)
	(segment
		(start 341.523574 -33.774888)
		(end 342.412066 -32.886396)
		(width 0.12954)
		(layer "B.Cu")
		(net "IRQ_SMI_ACTIVE_N")
	)
	(segment
		(start 335.13903 -40.836596)
		(end 335.158588 -40.836596)
		(width 0.0889)
		(layer "B.Cu")
		(net "IRQ_SMI_ACTIVE_N")
	)
	(segment
		(start 343.362026 -31.678372)
		(end 343.450418 -31.678372)
		(width 0.12954)
		(layer "B.Cu")
		(net "IRQ_SMI_ACTIVE_N")
	)
	(segment
		(start 339.377274 -36.803584)
		(end 339.377274 -35.479228)
		(width 0.12954)
		(layer "B.Cu")
		(net "IRQ_SMI_ACTIVE_N")
	)
	(segment
		(start 339.377274 -35.479228)
		(end 341.081614 -33.774888)
		(width 0.12954)
		(layer "B.Cu")
		(net "IRQ_SMI_ACTIVE_N")
	)
	(segment
		(start 334.325468 -42.18432)
		(end 334.38338 -42.242232)
		(width 0.0889)
		(layer "B.Cu")
		(net "IRQ_SMI_ACTIVE_N")
	)
	(segment
		(start 336.595466 -39.585392)
		(end 339.377274 -36.803584)
		(width 0.12954)
		(layer "B.Cu")
		(net "IRQ_SMI_ACTIVE_N")
	)
	(segment
		(start 343.450418 -30.636972)
		(end 343.450418 -31.678372)
		(width 0.12954)
		(layer "B.Cu")
		(net "IRQ_SMI_ACTIVE_N")
	)
	(segment
		(start 343.157556 -31.882842)
		(end 343.362026 -31.678372)
		(width 0.12954)
		(layer "B.Cu")
		(net "IRQ_SMI_ACTIVE_N")
	)
	(segment
		(start 335.110074 -40.83685)
		(end 335.13903 -40.836596)
		(width 0.0889)
		(layer "B.Cu")
		(net "IRQ_SMI_ACTIVE_N")
	)
	(segment
		(start 341.081614 -33.774888)
		(end 341.523574 -33.774888)
		(width 0.12954)
		(layer "B.Cu")
		(net "IRQ_SMI_ACTIVE_N")
	)
	(arc
		(start 334.650588 -41.119044)
		(mid 334.844551 -40.919699)
		(end 335.110074 -40.83685)
		(width 0.0889)
		(layer "B.Cu")
		(net "IRQ_SMI_ACTIVE_N")
	)
	(arc
		(start 334.38338 -42.242232)
		(mid 334.537781 -42.180856)
		(end 334.650588 -42.058844)
		(width 0.0889)
		(layer "B.Cu")
		(net "IRQ_SMI_ACTIVE_N")
	)
	(arc
		(start 335.463388 -40.649144)
		(mid 335.657982 -40.449309)
		(end 335.924398 -40.366696)
		(width 0.0889)
		(layer "B.Cu")
		(net "IRQ_SMI_ACTIVE_N")
	)
	(arc
		(start 335.973166 -40.366696)
		(mid 336.149784 -40.311827)
		(end 336.278728 -40.179244)
		(width 0.0889)
		(layer "B.Cu")
		(net "IRQ_SMI_ACTIVE_N")
	)
	(arc
		(start 334.650588 -42.058844)
		(mid 334.700629 -41.871646)
		(end 334.650588 -41.684448)
		(width 0.0889)
		(layer "B.Cu")
		(net "IRQ_SMI_ACTIVE_N")
	)
	(arc
		(start 334.650588 -41.684448)
		(mid 334.574914 -41.401746)
		(end 334.650588 -41.119044)
		(width 0.0889)
		(layer "B.Cu")
		(net "IRQ_SMI_ACTIVE_N")
	)
	(arc
		(start 335.158588 -40.836596)
		(mid 335.33479 -40.781563)
		(end 335.463388 -40.649144)
		(width 0.0889)
		(layer "B.Cu")
		(net "IRQ_SMI_ACTIVE_N")
	)
	(segment
		(start 193.83248 -11.090148)
		(end 193.83248 -12.283948)
		(width 0.12954)
		(layer "F.Cu")
		(net "IRQ_SMI_ACTIVE_BMC_N")
	)
	(segment
		(start 189.3824 -7.300468)
		(end 192.07988 -9.997948)
		(width 0.12954)
		(layer "F.Cu")
		(net "IRQ_SMI_ACTIVE_BMC_N")
	)
	(segment
		(start 192.07988 -9.997948)
		(end 192.74028 -9.997948)
		(width 0.12954)
		(layer "F.Cu")
		(net "IRQ_SMI_ACTIVE_BMC_N")
	)
	(segment
		(start 193.83248 -12.283948)
		(end 196.610986 -15.062454)
		(width 0.12954)
		(layer "F.Cu")
		(net "IRQ_SMI_ACTIVE_BMC_N")
	)
	(segment
		(start 137.60958 -7.300468)
		(end 189.3824 -7.300468)
		(width 0.12954)
		(layer "F.Cu")
		(net "IRQ_SMI_ACTIVE_BMC_N")
	)
	(segment
		(start 196.610986 -15.062454)
		(end 196.610986 -17.503648)
		(width 0.12954)
		(layer "F.Cu")
		(net "IRQ_SMI_ACTIVE_BMC_N")
	)
	(segment
		(start 137.08888 -7.821168)
		(end 137.60958 -7.300468)
		(width 0.12954)
		(layer "F.Cu")
		(net "IRQ_SMI_ACTIVE_BMC_N")
	)
	(segment
		(start 192.74028 -9.997948)
		(end 193.83248 -11.090148)
		(width 0.12954)
		(layer "F.Cu")
		(net "IRQ_SMI_ACTIVE_BMC_N")
	)
	(via
		(at 137.08888 -7.821168)
		(size 0.508)
		(drill 0.254)
		(layers "F.Cu" "B.Cu")
		(net "IRQ_SMI_ACTIVE_BMC_N")
	)
	(via
		(at 196.610986 -17.503648)
		(size 0.508)
		(drill 0.254)
		(layers "F.Cu" "B.Cu")
		(net "IRQ_SMI_ACTIVE_BMC_N")
	)
	(segment
		(start 345.268804 -18.000472)
		(end 345.268804 -27.710638)
		(width 0.12954)
		(layer "B.Cu")
		(net "IRQ_SMI_ACTIVE_BMC_N")
	)
	(segment
		(start 345.268804 -27.710638)
		(end 342.650318 -30.329124)
		(width 0.12954)
		(layer "B.Cu")
		(net "IRQ_SMI_ACTIVE_BMC_N")
	)
	(segment
		(start 325.583804 -16.303244)
		(end 327.6219 -14.265148)
		(width 0.12954)
		(layer "B.Cu")
		(net "IRQ_SMI_ACTIVE_BMC_N")
	)
	(segment
		(start 341.53348 -14.265148)
		(end 345.268804 -18.000472)
		(width 0.12954)
		(layer "B.Cu")
		(net "IRQ_SMI_ACTIVE_BMC_N")
	)
	(segment
		(start 258.787392 -41.747948)
		(end 261.347966 -39.187374)
		(width 0.12954)
		(layer "B.Cu")
		(net "IRQ_SMI_ACTIVE_BMC_N")
	)
	(segment
		(start 261.347966 -39.187374)
		(end 261.347966 -36.77793)
		(width 0.12954)
		(layer "B.Cu")
		(net "IRQ_SMI_ACTIVE_BMC_N")
	)
	(segment
		(start 205.80858 -16.436848)
		(end 211.87791 -22.506178)
		(width 0.12954)
		(layer "B.Cu")
		(net "IRQ_SMI_ACTIVE_BMC_N")
	)
	(segment
		(start 221.195138 -37.932106)
		(end 222.211138 -38.948106)
		(width 0.12954)
		(layer "B.Cu")
		(net "IRQ_SMI_ACTIVE_BMC_N")
	)
	(segment
		(start 196.610986 -17.503648)
		(end 197.677786 -16.436848)
		(width 0.12954)
		(layer "B.Cu")
		(net "IRQ_SMI_ACTIVE_BMC_N")
	)
	(segment
		(start 255.681734 -41.477692)
		(end 255.95199 -41.747948)
		(width 0.12954)
		(layer "B.Cu")
		(net "IRQ_SMI_ACTIVE_BMC_N")
	)
	(segment
		(start 214.0839 -35.278568)
		(end 216.737438 -37.932106)
		(width 0.12954)
		(layer "B.Cu")
		(net "IRQ_SMI_ACTIVE_BMC_N")
	)
	(segment
		(start 327.6219 -14.265148)
		(end 341.53348 -14.265148)
		(width 0.12954)
		(layer "B.Cu")
		(net "IRQ_SMI_ACTIVE_BMC_N")
	)
	(segment
		(start 270.905224 -32.723328)
		(end 274.380706 -29.247846)
		(width 0.12954)
		(layer "B.Cu")
		(net "IRQ_SMI_ACTIVE_BMC_N")
	)
	(segment
		(start 265.402568 -32.723328)
		(end 270.905224 -32.723328)
		(width 0.12954)
		(layer "B.Cu")
		(net "IRQ_SMI_ACTIVE_BMC_N")
	)
	(segment
		(start 249.333512 -41.477692)
		(end 255.681734 -41.477692)
		(width 0.12954)
		(layer "B.Cu")
		(net "IRQ_SMI_ACTIVE_BMC_N")
	)
	(segment
		(start 241.55908 -43.068748)
		(end 242.14328 -43.652948)
		(width 0.12954)
		(layer "B.Cu")
		(net "IRQ_SMI_ACTIVE_BMC_N")
	)
	(segment
		(start 197.677786 -16.436848)
		(end 205.80858 -16.436848)
		(width 0.12954)
		(layer "B.Cu")
		(net "IRQ_SMI_ACTIVE_BMC_N")
	)
	(segment
		(start 214.0839 -28.993084)
		(end 214.0839 -35.278568)
		(width 0.12954)
		(layer "B.Cu")
		(net "IRQ_SMI_ACTIVE_BMC_N")
	)
	(segment
		(start 287.919668 -22.321774)
		(end 295.468802 -22.321774)
		(width 0.12954)
		(layer "B.Cu")
		(net "IRQ_SMI_ACTIVE_BMC_N")
	)
	(segment
		(start 274.380706 -29.247846)
		(end 280.993596 -29.247846)
		(width 0.12954)
		(layer "B.Cu")
		(net "IRQ_SMI_ACTIVE_BMC_N")
	)
	(segment
		(start 242.14328 -43.652948)
		(end 247.158256 -43.652948)
		(width 0.12954)
		(layer "B.Cu")
		(net "IRQ_SMI_ACTIVE_BMC_N")
	)
	(segment
		(start 255.95199 -41.747948)
		(end 258.787392 -41.747948)
		(width 0.12954)
		(layer "B.Cu")
		(net "IRQ_SMI_ACTIVE_BMC_N")
	)
	(segment
		(start 301.487332 -16.303244)
		(end 325.583804 -16.303244)
		(width 0.12954)
		(layer "B.Cu")
		(net "IRQ_SMI_ACTIVE_BMC_N")
	)
	(segment
		(start 247.158256 -43.652948)
		(end 249.333512 -41.477692)
		(width 0.12954)
		(layer "B.Cu")
		(net "IRQ_SMI_ACTIVE_BMC_N")
	)
	(segment
		(start 261.347966 -36.77793)
		(end 265.402568 -32.723328)
		(width 0.12954)
		(layer "B.Cu")
		(net "IRQ_SMI_ACTIVE_BMC_N")
	)
	(segment
		(start 232.721912 -41.57218)
		(end 236.334808 -43.068748)
		(width 0.12954)
		(layer "B.Cu")
		(net "IRQ_SMI_ACTIVE_BMC_N")
	)
	(segment
		(start 236.334808 -43.068748)
		(end 241.55908 -43.068748)
		(width 0.12954)
		(layer "B.Cu")
		(net "IRQ_SMI_ACTIVE_BMC_N")
	)
	(segment
		(start 211.87791 -26.787094)
		(end 214.0839 -28.993084)
		(width 0.12954)
		(layer "B.Cu")
		(net "IRQ_SMI_ACTIVE_BMC_N")
	)
	(segment
		(start 295.468802 -22.321774)
		(end 301.487332 -16.303244)
		(width 0.12954)
		(layer "B.Cu")
		(net "IRQ_SMI_ACTIVE_BMC_N")
	)
	(segment
		(start 342.650318 -30.329124)
		(end 342.650318 -30.636972)
		(width 0.12954)
		(layer "B.Cu")
		(net "IRQ_SMI_ACTIVE_BMC_N")
	)
	(segment
		(start 230.097838 -38.948106)
		(end 232.721912 -41.57218)
		(width 0.12954)
		(layer "B.Cu")
		(net "IRQ_SMI_ACTIVE_BMC_N")
	)
	(segment
		(start 137.08888 -8.962898)
		(end 137.08888 -7.821168)
		(width 0.12954)
		(layer "B.Cu")
		(net "IRQ_SMI_ACTIVE_BMC_N")
	)
	(segment
		(start 211.87791 -22.506178)
		(end 211.87791 -26.787094)
		(width 0.12954)
		(layer "B.Cu")
		(net "IRQ_SMI_ACTIVE_BMC_N")
	)
	(segment
		(start 280.993596 -29.247846)
		(end 287.919668 -22.321774)
		(width 0.12954)
		(layer "B.Cu")
		(net "IRQ_SMI_ACTIVE_BMC_N")
	)
	(segment
		(start 216.737438 -37.932106)
		(end 221.195138 -37.932106)
		(width 0.12954)
		(layer "B.Cu")
		(net "IRQ_SMI_ACTIVE_BMC_N")
	)
	(segment
		(start 222.211138 -38.948106)
		(end 230.097838 -38.948106)
		(width 0.12954)
		(layer "B.Cu")
		(net "IRQ_SMI_ACTIVE_BMC_N")
	)
	(segment
		(start 191.02451 -113.579148)
		(end 192.98031 -115.534948)
		(width 0.12954)
		(layer "F.Cu")
		(net "IRQ_SGPIO_INTR_N_R")
	)
	(segment
		(start 187.152026 -113.579148)
		(end 190.55588 -113.579148)
		(width 0.12954)
		(layer "F.Cu")
		(net "IRQ_SGPIO_INTR_N_R")
	)
	(segment
		(start 190.55588 -113.579148)
		(end 191.02451 -113.579148)
		(width 0.12954)
		(layer "F.Cu")
		(net "IRQ_SGPIO_INTR_N_R")
	)
	(segment
		(start 186.955684 -113.77549)
		(end 187.152026 -113.579148)
		(width 0.12954)
		(layer "F.Cu")
		(net "IRQ_SGPIO_INTR_N_R")
	)
	(via
		(at 190.55588 -113.579148)
		(size 0.762)
		(drill 0.381)
		(layers "F.Cu" "B.Cu")
		(net "IRQ_SGPIO_INTR_N_R")
	)
	(segment
		(start 129.88417 -45.415708)
		(end 129.88417 -33.526476)
		(width 0.12954)
		(layer "F.Cu")
		(net "IRQ_SGPIO_INTR_N")
	)
	(segment
		(start 144.526 -28.158948)
		(end 149.098 -23.586948)
		(width 0.12954)
		(layer "F.Cu")
		(net "IRQ_SGPIO_INTR_N")
	)
	(segment
		(start 131.767834 -31.642812)
		(end 137.944606 -31.642812)
		(width 0.12954)
		(layer "F.Cu")
		(net "IRQ_SGPIO_INTR_N")
	)
	(segment
		(start 138.27506 -53.806598)
		(end 129.88417 -45.415708)
		(width 0.12954)
		(layer "F.Cu")
		(net "IRQ_SGPIO_INTR_N")
	)
	(segment
		(start 193.78041 -115.534948)
		(end 194.39001 -115.534948)
		(width 0.12954)
		(layer "F.Cu")
		(net "IRQ_SGPIO_INTR_N")
	)
	(segment
		(start 149.098 -16.642842)
		(end 150.266146 -15.474696)
		(width 0.12954)
		(layer "F.Cu")
		(net "IRQ_SGPIO_INTR_N")
	)
	(segment
		(start 149.098 -23.586948)
		(end 149.098 -16.642842)
		(width 0.12954)
		(layer "F.Cu")
		(net "IRQ_SGPIO_INTR_N")
	)
	(segment
		(start 152.0571 -15.633954)
		(end 152.0571 -16.550132)
		(width 0.12954)
		(layer "F.Cu")
		(net "IRQ_SGPIO_INTR_N")
	)
	(segment
		(start 138.27506 -60.074048)
		(end 138.27506 -53.806598)
		(width 0.12954)
		(layer "F.Cu")
		(net "IRQ_SGPIO_INTR_N")
	)
	(segment
		(start 150.266146 -15.474696)
		(end 151.897842 -15.474696)
		(width 0.12954)
		(layer "F.Cu")
		(net "IRQ_SGPIO_INTR_N")
	)
	(segment
		(start 129.88417 -33.526476)
		(end 131.767834 -31.642812)
		(width 0.12954)
		(layer "F.Cu")
		(net "IRQ_SGPIO_INTR_N")
	)
	(segment
		(start 137.944606 -31.642812)
		(end 141.42847 -28.158948)
		(width 0.12954)
		(layer "F.Cu")
		(net "IRQ_SGPIO_INTR_N")
	)
	(segment
		(start 141.42847 -28.158948)
		(end 144.526 -28.158948)
		(width 0.12954)
		(layer "F.Cu")
		(net "IRQ_SGPIO_INTR_N")
	)
	(segment
		(start 151.897842 -15.474696)
		(end 152.0571 -15.633954)
		(width 0.12954)
		(layer "F.Cu")
		(net "IRQ_SGPIO_INTR_N")
	)
	(via
		(at 138.27506 -60.074048)
		(size 0.762)
		(drill 0.254)
		(layers "F.Cu" "B.Cu")
		(net "IRQ_SGPIO_INTR_N")
	)
	(via
		(at 194.39001 -115.534948)
		(size 0.508)
		(drill 0.254)
		(layers "F.Cu" "B.Cu")
		(net "IRQ_SGPIO_INTR_N")
	)
	(segment
		(start 193.27368 -115.534948)
		(end 191.644016 -113.905284)
		(width 0.127)
		(layer "In4.Cu")
		(net "IRQ_SGPIO_INTR_N")
	)
	(segment
		(start 189.39256 -94.680532)
		(end 189.39256 -86.963504)
		(width 0.127)
		(layer "In4.Cu")
		(net "IRQ_SGPIO_INTR_N")
	)
	(segment
		(start 194.39001 -115.534948)
		(end 193.27368 -115.534948)
		(width 0.127)
		(layer "In4.Cu")
		(net "IRQ_SGPIO_INTR_N")
	)
	(segment
		(start 142.929864 -70.576948)
		(end 138.27506 -65.922144)
		(width 0.127)
		(layer "In4.Cu")
		(net "IRQ_SGPIO_INTR_N")
	)
	(segment
		(start 138.27506 -65.922144)
		(end 138.27506 -60.074048)
		(width 0.127)
		(layer "In4.Cu")
		(net "IRQ_SGPIO_INTR_N")
	)
	(segment
		(start 191.644016 -113.905284)
		(end 191.644016 -96.931988)
		(width 0.127)
		(layer "In4.Cu")
		(net "IRQ_SGPIO_INTR_N")
	)
	(segment
		(start 161.560764 -70.576948)
		(end 142.929864 -70.576948)
		(width 0.127)
		(layer "In4.Cu")
		(net "IRQ_SGPIO_INTR_N")
	)
	(segment
		(start 176.829466 -85.84565)
		(end 161.560764 -70.576948)
		(width 0.127)
		(layer "In4.Cu")
		(net "IRQ_SGPIO_INTR_N")
	)
	(segment
		(start 189.39256 -86.963504)
		(end 188.274706 -85.84565)
		(width 0.127)
		(layer "In4.Cu")
		(net "IRQ_SGPIO_INTR_N")
	)
	(segment
		(start 188.274706 -85.84565)
		(end 176.829466 -85.84565)
		(width 0.127)
		(layer "In4.Cu")
		(net "IRQ_SGPIO_INTR_N")
	)
	(segment
		(start 191.644016 -96.931988)
		(end 189.39256 -94.680532)
		(width 0.127)
		(layer "In4.Cu")
		(net "IRQ_SGPIO_INTR_N")
	)
	(segment
		(start 21.580856 -168.583356)
		(end 21.73351 -168.583356)
		(width 0.12954)
		(layer "F.Cu")
		(net "IRQ_PVCCD_CPU1_VRHOT_LVC3_N")
	)
	(segment
		(start 21.1455 -169.018712)
		(end 21.580856 -168.583356)
		(width 0.12954)
		(layer "F.Cu")
		(net "IRQ_PVCCD_CPU1_VRHOT_LVC3_N")
	)
	(segment
		(start 22.723094 -168.581324)
		(end 21.735542 -168.581324)
		(width 0.12954)
		(layer "F.Cu")
		(net "IRQ_PVCCD_CPU1_VRHOT_LVC3_N")
	)
	(segment
		(start 186.155584 -114.575336)
		(end 186.555634 -114.975386)
		(width 0.12954)
		(layer "F.Cu")
		(net "IRQ_PVCCD_CPU1_VRHOT_LVC3_N")
	)
	(segment
		(start 21.735542 -168.581324)
		(end 21.73351 -168.583356)
		(width 0.12954)
		(layer "F.Cu")
		(net "IRQ_PVCCD_CPU1_VRHOT_LVC3_N")
	)
	(via
		(at 186.555634 -114.975386)
		(size 0.4572)
		(drill 0.254)
		(layers "F.Cu" "B.Cu")
		(net "IRQ_PVCCD_CPU1_VRHOT_LVC3_N")
	)
	(via
		(at 188.32068 -125.517148)
		(size 0.508)
		(drill 0.254)
		(layers "F.Cu" "B.Cu")
		(net "IRQ_PVCCD_CPU1_VRHOT_LVC3_N")
	)
	(via
		(at 21.1455 -169.018712)
		(size 0.508)
		(drill 0.254)
		(layers "F.Cu" "B.Cu")
		(net "IRQ_PVCCD_CPU1_VRHOT_LVC3_N")
	)
	(segment
		(start 188.32068 -115.636548)
		(end 187.659518 -114.975386)
		(width 0.127)
		(layer "In11.Cu")
		(net "IRQ_PVCCD_CPU1_VRHOT_LVC3_N")
	)
	(segment
		(start 188.32068 -122.136408)
		(end 187.56884 -121.384568)
		(width 0.127)
		(layer "In11.Cu")
		(net "IRQ_PVCCD_CPU1_VRHOT_LVC3_N")
	)
	(segment
		(start 187.56884 -121.384568)
		(end 187.56884 -120.198388)
		(width 0.127)
		(layer "In11.Cu")
		(net "IRQ_PVCCD_CPU1_VRHOT_LVC3_N")
	)
	(segment
		(start 187.659518 -114.975386)
		(end 186.555634 -114.975386)
		(width 0.127)
		(layer "In11.Cu")
		(net "IRQ_PVCCD_CPU1_VRHOT_LVC3_N")
	)
	(segment
		(start 188.32068 -125.517148)
		(end 188.32068 -122.136408)
		(width 0.127)
		(layer "In11.Cu")
		(net "IRQ_PVCCD_CPU1_VRHOT_LVC3_N")
	)
	(segment
		(start 187.56884 -120.198388)
		(end 188.32068 -119.446548)
		(width 0.127)
		(layer "In11.Cu")
		(net "IRQ_PVCCD_CPU1_VRHOT_LVC3_N")
	)
	(segment
		(start 188.32068 -119.446548)
		(end 188.32068 -115.636548)
		(width 0.127)
		(layer "In11.Cu")
		(net "IRQ_PVCCD_CPU1_VRHOT_LVC3_N")
	)
	(segment
		(start 188.32068 -125.517148)
		(end 187.30468 -126.533148)
		(width 0.127)
		(layer "In13.Cu")
		(net "IRQ_PVCCD_CPU1_VRHOT_LVC3_N")
	)
	(segment
		(start 18.3261 -152.123648)
		(end 24.6507 -158.448248)
		(width 0.127)
		(layer "In13.Cu")
		(net "IRQ_PVCCD_CPU1_VRHOT_LVC3_N")
	)
	(segment
		(start 132.356606 -117.114574)
		(end 132.03682 -116.794788)
		(width 0.127)
		(layer "In13.Cu")
		(net "IRQ_PVCCD_CPU1_VRHOT_LVC3_N")
	)
	(segment
		(start 104.30256 -120.881648)
		(end 49.29378 -120.881648)
		(width 0.127)
		(layer "In13.Cu")
		(net "IRQ_PVCCD_CPU1_VRHOT_LVC3_N")
	)
	(segment
		(start 154.827732 -123.063)
		(end 154.56916 -122.804428)
		(width 0.127)
		(layer "In13.Cu")
		(net "IRQ_PVCCD_CPU1_VRHOT_LVC3_N")
	)
	(segment
		(start 168.686988 -126.533148)
		(end 167.620188 -125.466348)
		(width 0.127)
		(layer "In13.Cu")
		(net "IRQ_PVCCD_CPU1_VRHOT_LVC3_N")
	)
	(segment
		(start 24.6507 -164.297868)
		(end 23.328376 -165.620192)
		(width 0.127)
		(layer "In13.Cu")
		(net "IRQ_PVCCD_CPU1_VRHOT_LVC3_N")
	)
	(segment
		(start 151.63038 -122.804428)
		(end 151.21636 -122.390408)
		(width 0.127)
		(layer "In13.Cu")
		(net "IRQ_PVCCD_CPU1_VRHOT_LVC3_N")
	)
	(segment
		(start 165.23208 -125.466348)
		(end 164.3253 -124.559568)
		(width 0.127)
		(layer "In13.Cu")
		(net "IRQ_PVCCD_CPU1_VRHOT_LVC3_N")
	)
	(segment
		(start 144.74698 -122.390408)
		(end 140.081 -117.724428)
		(width 0.127)
		(layer "In13.Cu")
		(net "IRQ_PVCCD_CPU1_VRHOT_LVC3_N")
	)
	(segment
		(start 25.19934 -119.827548)
		(end 18.3261 -126.700788)
		(width 0.127)
		(layer "In13.Cu")
		(net "IRQ_PVCCD_CPU1_VRHOT_LVC3_N")
	)
	(segment
		(start 49.29378 -120.881648)
		(end 48.23968 -119.827548)
		(width 0.127)
		(layer "In13.Cu")
		(net "IRQ_PVCCD_CPU1_VRHOT_LVC3_N")
	)
	(segment
		(start 158.2928 -123.063)
		(end 154.827732 -123.063)
		(width 0.127)
		(layer "In13.Cu")
		(net "IRQ_PVCCD_CPU1_VRHOT_LVC3_N")
	)
	(segment
		(start 167.620188 -125.466348)
		(end 165.23208 -125.466348)
		(width 0.127)
		(layer "In13.Cu")
		(net "IRQ_PVCCD_CPU1_VRHOT_LVC3_N")
	)
	(segment
		(start 48.23968 -119.827548)
		(end 25.19934 -119.827548)
		(width 0.127)
		(layer "In13.Cu")
		(net "IRQ_PVCCD_CPU1_VRHOT_LVC3_N")
	)
	(segment
		(start 187.30468 -126.533148)
		(end 168.686988 -126.533148)
		(width 0.127)
		(layer "In13.Cu")
		(net "IRQ_PVCCD_CPU1_VRHOT_LVC3_N")
	)
	(segment
		(start 137.65276 -117.724428)
		(end 137.042906 -117.114574)
		(width 0.127)
		(layer "In13.Cu")
		(net "IRQ_PVCCD_CPU1_VRHOT_LVC3_N")
	)
	(segment
		(start 23.328376 -166.835836)
		(end 21.1455 -169.018712)
		(width 0.127)
		(layer "In13.Cu")
		(net "IRQ_PVCCD_CPU1_VRHOT_LVC3_N")
	)
	(segment
		(start 23.328376 -165.620192)
		(end 23.328376 -166.835836)
		(width 0.127)
		(layer "In13.Cu")
		(net "IRQ_PVCCD_CPU1_VRHOT_LVC3_N")
	)
	(segment
		(start 159.789368 -124.559568)
		(end 158.2928 -123.063)
		(width 0.127)
		(layer "In13.Cu")
		(net "IRQ_PVCCD_CPU1_VRHOT_LVC3_N")
	)
	(segment
		(start 154.56916 -122.804428)
		(end 151.63038 -122.804428)
		(width 0.127)
		(layer "In13.Cu")
		(net "IRQ_PVCCD_CPU1_VRHOT_LVC3_N")
	)
	(segment
		(start 24.6507 -158.448248)
		(end 24.6507 -164.297868)
		(width 0.127)
		(layer "In13.Cu")
		(net "IRQ_PVCCD_CPU1_VRHOT_LVC3_N")
	)
	(segment
		(start 108.38942 -116.794788)
		(end 104.30256 -120.881648)
		(width 0.127)
		(layer "In13.Cu")
		(net "IRQ_PVCCD_CPU1_VRHOT_LVC3_N")
	)
	(segment
		(start 137.042906 -117.114574)
		(end 132.356606 -117.114574)
		(width 0.127)
		(layer "In13.Cu")
		(net "IRQ_PVCCD_CPU1_VRHOT_LVC3_N")
	)
	(segment
		(start 164.3253 -124.559568)
		(end 159.789368 -124.559568)
		(width 0.127)
		(layer "In13.Cu")
		(net "IRQ_PVCCD_CPU1_VRHOT_LVC3_N")
	)
	(segment
		(start 132.03682 -116.794788)
		(end 108.38942 -116.794788)
		(width 0.127)
		(layer "In13.Cu")
		(net "IRQ_PVCCD_CPU1_VRHOT_LVC3_N")
	)
	(segment
		(start 140.081 -117.724428)
		(end 137.65276 -117.724428)
		(width 0.127)
		(layer "In13.Cu")
		(net "IRQ_PVCCD_CPU1_VRHOT_LVC3_N")
	)
	(segment
		(start 151.21636 -122.390408)
		(end 144.74698 -122.390408)
		(width 0.127)
		(layer "In13.Cu")
		(net "IRQ_PVCCD_CPU1_VRHOT_LVC3_N")
	)
	(segment
		(start 18.3261 -126.700788)
		(end 18.3261 -152.123648)
		(width 0.127)
		(layer "In13.Cu")
		(net "IRQ_PVCCD_CPU1_VRHOT_LVC3_N")
	)
	(segment
		(start 438.862216 -122.089926)
		(end 438.405016 -121.632726)
		(width 0.12954)
		(layer "F.Cu")
		(net "IRQ_PVCCD_CPU0_VRHOT_LVC3_N")
	)
	(segment
		(start 438.862216 -122.089926)
		(end 438.862216 -117.211348)
		(width 0.12954)
		(layer "F.Cu")
		(net "IRQ_PVCCD_CPU0_VRHOT_LVC3_N")
	)
	(segment
		(start 433.555648 -115.481354)
		(end 432.486054 -116.550948)
		(width 0.12954)
		(layer "F.Cu")
		(net "IRQ_PVCCD_CPU0_VRHOT_LVC3_N")
	)
	(segment
		(start 432.486054 -116.550948)
		(end 430.96688 -116.550948)
		(width 0.12954)
		(layer "F.Cu")
		(net "IRQ_PVCCD_CPU0_VRHOT_LVC3_N")
	)
	(segment
		(start 438.862216 -117.211348)
		(end 437.132222 -115.481354)
		(width 0.12954)
		(layer "F.Cu")
		(net "IRQ_PVCCD_CPU0_VRHOT_LVC3_N")
	)
	(segment
		(start 437.132222 -115.481354)
		(end 433.555648 -115.481354)
		(width 0.12954)
		(layer "F.Cu")
		(net "IRQ_PVCCD_CPU0_VRHOT_LVC3_N")
	)
	(segment
		(start 186.155584 -107.375452)
		(end 186.555634 -106.975402)
		(width 0.12954)
		(layer "F.Cu")
		(net "IRQ_PVCCD_CPU0_VRHOT_LVC3_N")
	)
	(segment
		(start 430.96688 -116.550948)
		(end 430.20488 -115.788948)
		(width 0.12954)
		(layer "F.Cu")
		(net "IRQ_PVCCD_CPU0_VRHOT_LVC3_N")
	)
	(segment
		(start 438.405016 -121.632726)
		(end 437.643016 -121.632726)
		(width 0.12954)
		(layer "F.Cu")
		(net "IRQ_PVCCD_CPU0_VRHOT_LVC3_N")
	)
	(via
		(at 430.20488 -115.788948)
		(size 0.508)
		(drill 0.254)
		(layers "F.Cu" "B.Cu")
		(net "IRQ_PVCCD_CPU0_VRHOT_LVC3_N")
	)
	(via
		(at 186.555634 -106.975402)
		(size 0.4572)
		(drill 0.254)
		(layers "F.Cu" "B.Cu")
		(net "IRQ_PVCCD_CPU0_VRHOT_LVC3_N")
	)
	(via
		(at 373.30888 -110.373668)
		(size 0.508)
		(drill 0.254)
		(layers "F.Cu" "B.Cu")
		(net "IRQ_PVCCD_CPU0_VRHOT_LVC3_N")
	)
	(segment
		(start 373.82196 -110.886748)
		(end 381.1778 -110.886748)
		(width 0.127)
		(layer "In4.Cu")
		(net "IRQ_PVCCD_CPU0_VRHOT_LVC3_N")
	)
	(segment
		(start 406.21966 -109.852968)
		(end 412.15564 -115.788948)
		(width 0.127)
		(layer "In4.Cu")
		(net "IRQ_PVCCD_CPU0_VRHOT_LVC3_N")
	)
	(segment
		(start 412.15564 -115.788948)
		(end 430.20488 -115.788948)
		(width 0.127)
		(layer "In4.Cu")
		(net "IRQ_PVCCD_CPU0_VRHOT_LVC3_N")
	)
	(segment
		(start 373.30888 -110.373668)
		(end 373.82196 -110.886748)
		(width 0.127)
		(layer "In4.Cu")
		(net "IRQ_PVCCD_CPU0_VRHOT_LVC3_N")
	)
	(segment
		(start 382.21158 -109.852968)
		(end 406.21966 -109.852968)
		(width 0.127)
		(layer "In4.Cu")
		(net "IRQ_PVCCD_CPU0_VRHOT_LVC3_N")
	)
	(segment
		(start 381.1778 -110.886748)
		(end 382.21158 -109.852968)
		(width 0.127)
		(layer "In4.Cu")
		(net "IRQ_PVCCD_CPU0_VRHOT_LVC3_N")
	)
	(segment
		(start 189.98184 -103.180388)
		(end 189.98184 -104.3432)
		(width 0.127)
		(layer "In15.Cu")
		(net "IRQ_PVCCD_CPU0_VRHOT_LVC3_N")
	)
	(segment
		(start 265.867388 -113.795048)
		(end 252.19152 -113.795048)
		(width 0.127)
		(layer "In15.Cu")
		(net "IRQ_PVCCD_CPU0_VRHOT_LVC3_N")
	)
	(segment
		(start 221.757748 -96.54794)
		(end 219.94622 -96.54794)
		(width 0.127)
		(layer "In15.Cu")
		(net "IRQ_PVCCD_CPU0_VRHOT_LVC3_N")
	)
	(segment
		(start 232.002076 -99.959668)
		(end 225.169476 -99.959668)
		(width 0.127)
		(layer "In15.Cu")
		(net "IRQ_PVCCD_CPU0_VRHOT_LVC3_N")
	)
	(segment
		(start 373.30888 -110.373668)
		(end 326.7456 -110.373668)
		(width 0.127)
		(layer "In15.Cu")
		(net "IRQ_PVCCD_CPU0_VRHOT_LVC3_N")
	)
	(segment
		(start 219.780612 -96.713548)
		(end 209.696812 -96.713548)
		(width 0.127)
		(layer "In15.Cu")
		(net "IRQ_PVCCD_CPU0_VRHOT_LVC3_N")
	)
	(segment
		(start 267.200888 -112.461548)
		(end 265.867388 -113.795048)
		(width 0.127)
		(layer "In15.Cu")
		(net "IRQ_PVCCD_CPU0_VRHOT_LVC3_N")
	)
	(segment
		(start 324.33768 -107.965748)
		(end 283.379164 -107.965748)
		(width 0.127)
		(layer "In15.Cu")
		(net "IRQ_PVCCD_CPU0_VRHOT_LVC3_N")
	)
	(segment
		(start 195.55968 -97.602548)
		(end 189.98184 -103.180388)
		(width 0.127)
		(layer "In15.Cu")
		(net "IRQ_PVCCD_CPU0_VRHOT_LVC3_N")
	)
	(segment
		(start 208.807812 -97.602548)
		(end 195.55968 -97.602548)
		(width 0.127)
		(layer "In15.Cu")
		(net "IRQ_PVCCD_CPU0_VRHOT_LVC3_N")
	)
	(segment
		(start 187.349638 -106.975402)
		(end 186.555634 -106.975402)
		(width 0.127)
		(layer "In15.Cu")
		(net "IRQ_PVCCD_CPU0_VRHOT_LVC3_N")
	)
	(segment
		(start 209.696812 -96.713548)
		(end 208.807812 -97.602548)
		(width 0.127)
		(layer "In15.Cu")
		(net "IRQ_PVCCD_CPU0_VRHOT_LVC3_N")
	)
	(segment
		(start 326.7456 -110.373668)
		(end 324.33768 -107.965748)
		(width 0.127)
		(layer "In15.Cu")
		(net "IRQ_PVCCD_CPU0_VRHOT_LVC3_N")
	)
	(segment
		(start 242.208558 -103.812086)
		(end 235.854494 -103.812086)
		(width 0.127)
		(layer "In15.Cu")
		(net "IRQ_PVCCD_CPU0_VRHOT_LVC3_N")
	)
	(segment
		(start 283.379164 -107.965748)
		(end 278.883364 -112.461548)
		(width 0.127)
		(layer "In15.Cu")
		(net "IRQ_PVCCD_CPU0_VRHOT_LVC3_N")
	)
	(segment
		(start 278.883364 -112.461548)
		(end 267.200888 -112.461548)
		(width 0.127)
		(layer "In15.Cu")
		(net "IRQ_PVCCD_CPU0_VRHOT_LVC3_N")
	)
	(segment
		(start 252.19152 -113.795048)
		(end 242.208558 -103.812086)
		(width 0.127)
		(layer "In15.Cu")
		(net "IRQ_PVCCD_CPU0_VRHOT_LVC3_N")
	)
	(segment
		(start 235.854494 -103.812086)
		(end 232.002076 -99.959668)
		(width 0.127)
		(layer "In15.Cu")
		(net "IRQ_PVCCD_CPU0_VRHOT_LVC3_N")
	)
	(segment
		(start 189.98184 -104.3432)
		(end 187.349638 -106.975402)
		(width 0.127)
		(layer "In15.Cu")
		(net "IRQ_PVCCD_CPU0_VRHOT_LVC3_N")
	)
	(segment
		(start 219.94622 -96.54794)
		(end 219.780612 -96.713548)
		(width 0.127)
		(layer "In15.Cu")
		(net "IRQ_PVCCD_CPU0_VRHOT_LVC3_N")
	)
	(segment
		(start 225.169476 -99.959668)
		(end 221.757748 -96.54794)
		(width 0.127)
		(layer "In15.Cu")
		(net "IRQ_PVCCD_CPU0_VRHOT_LVC3_N")
	)
	(segment
		(start 206.390748 -116.220748)
		(end 196.17436 -116.220748)
		(width 0.12954)
		(layer "F.Cu")
		(net "IRQ_PSYS_CRIT_N")
	)
	(segment
		(start 190.9572 -114.158268)
		(end 186.538362 -114.158268)
		(width 0.12954)
		(layer "F.Cu")
		(net "IRQ_PSYS_CRIT_N")
	)
	(segment
		(start 347.328744 -359.767632)
		(end 347.574108 -360.012996)
		(width 0.12954)
		(layer "F.Cu")
		(net "IRQ_PSYS_CRIT_N")
	)
	(segment
		(start 347.328744 -359.353612)
		(end 347.328744 -359.767632)
		(width 0.12954)
		(layer "F.Cu")
		(net "IRQ_PSYS_CRIT_N")
	)
	(segment
		(start 206.9338 -116.7638)
		(end 206.390748 -116.220748)
		(width 0.12954)
		(layer "F.Cu")
		(net "IRQ_PSYS_CRIT_N")
	)
	(segment
		(start 196.17436 -116.220748)
		(end 196.01688 -116.063268)
		(width 0.12954)
		(layer "F.Cu")
		(net "IRQ_PSYS_CRIT_N")
	)
	(segment
		(start 192.21196 -115.794028)
		(end 192.21196 -115.413028)
		(width 0.12954)
		(layer "F.Cu")
		(net "IRQ_PSYS_CRIT_N")
	)
	(segment
		(start 347.574108 -360.012996)
		(end 347.992954 -360.012996)
		(width 0.12954)
		(layer "F.Cu")
		(net "IRQ_PSYS_CRIT_N")
	)
	(segment
		(start 192.4812 -116.063268)
		(end 192.21196 -115.794028)
		(width 0.12954)
		(layer "F.Cu")
		(net "IRQ_PSYS_CRIT_N")
	)
	(segment
		(start 196.01688 -116.063268)
		(end 192.4812 -116.063268)
		(width 0.12954)
		(layer "F.Cu")
		(net "IRQ_PSYS_CRIT_N")
	)
	(segment
		(start 210.028028 -116.7638)
		(end 206.9338 -116.7638)
		(width 0.12954)
		(layer "F.Cu")
		(net "IRQ_PSYS_CRIT_N")
	)
	(segment
		(start 192.21196 -115.413028)
		(end 190.9572 -114.158268)
		(width 0.12954)
		(layer "F.Cu")
		(net "IRQ_PSYS_CRIT_N")
	)
	(segment
		(start 211.25688 -116.2558)
		(end 210.536028 -116.2558)
		(width 0.12954)
		(layer "F.Cu")
		(net "IRQ_PSYS_CRIT_N")
	)
	(segment
		(start 186.538362 -114.158268)
		(end 186.155584 -113.77549)
		(width 0.12954)
		(layer "F.Cu")
		(net "IRQ_PSYS_CRIT_N")
	)
	(segment
		(start 210.536028 -116.2558)
		(end 210.028028 -116.7638)
		(width 0.12954)
		(layer "F.Cu")
		(net "IRQ_PSYS_CRIT_N")
	)
	(via
		(at 304.430684 -387.270752)
		(size 0.508)
		(drill 0.254)
		(layers "F.Cu" "B.Cu")
		(net "IRQ_PSYS_CRIT_N")
	)
	(via
		(at 347.328744 -359.353612)
		(size 0.508)
		(drill 0.254)
		(layers "F.Cu" "B.Cu")
		(net "IRQ_PSYS_CRIT_N")
	)
	(via
		(at 211.25688 -116.2558)
		(size 0.508)
		(drill 0.254)
		(layers "F.Cu" "B.Cu")
		(net "IRQ_PSYS_CRIT_N")
	)
	(via
		(at 241.34826 -201.011028)
		(size 0.508)
		(drill 0.254)
		(layers "F.Cu" "B.Cu")
		(net "IRQ_PSYS_CRIT_N")
	)
	(segment
		(start 249.48388 -281.087068)
		(end 249.48388 -327.426828)
		(width 0.127)
		(layer "In4.Cu")
		(net "IRQ_PSYS_CRIT_N")
	)
	(segment
		(start 252.02388 -211.686648)
		(end 252.02388 -278.547068)
		(width 0.127)
		(layer "In4.Cu")
		(net "IRQ_PSYS_CRIT_N")
	)
	(segment
		(start 296.728134 -382.615948)
		(end 301.382938 -387.270752)
		(width 0.127)
		(layer "In4.Cu")
		(net "IRQ_PSYS_CRIT_N")
	)
	(segment
		(start 252.02388 -278.547068)
		(end 249.48388 -281.087068)
		(width 0.127)
		(layer "In4.Cu")
		(net "IRQ_PSYS_CRIT_N")
	)
	(segment
		(start 301.382938 -387.270752)
		(end 304.430684 -387.270752)
		(width 0.127)
		(layer "In4.Cu")
		(net "IRQ_PSYS_CRIT_N")
	)
	(segment
		(start 281.08656 -373.620792)
		(end 290.081716 -382.615948)
		(width 0.127)
		(layer "In4.Cu")
		(net "IRQ_PSYS_CRIT_N")
	)
	(segment
		(start 281.08656 -359.029508)
		(end 281.08656 -373.620792)
		(width 0.127)
		(layer "In4.Cu")
		(net "IRQ_PSYS_CRIT_N")
	)
	(segment
		(start 241.34826 -201.011028)
		(end 252.02388 -211.686648)
		(width 0.127)
		(layer "In4.Cu")
		(net "IRQ_PSYS_CRIT_N")
	)
	(segment
		(start 290.081716 -382.615948)
		(end 296.728134 -382.615948)
		(width 0.127)
		(layer "In4.Cu")
		(net "IRQ_PSYS_CRIT_N")
	)
	(segment
		(start 249.48388 -327.426828)
		(end 281.08656 -359.029508)
		(width 0.127)
		(layer "In4.Cu")
		(net "IRQ_PSYS_CRIT_N")
	)
	(segment
		(start 346.258642 -374.186196)
		(end 331.073252 -374.186196)
		(width 0.127)
		(layer "In6.Cu")
		(net "IRQ_PSYS_CRIT_N")
	)
	(segment
		(start 347.328744 -359.353612)
		(end 346.931234 -359.751122)
		(width 0.127)
		(layer "In6.Cu")
		(net "IRQ_PSYS_CRIT_N")
	)
	(segment
		(start 345.78798 -363.878368)
		(end 349.03156 -367.121948)
		(width 0.127)
		(layer "In6.Cu")
		(net "IRQ_PSYS_CRIT_N")
	)
	(segment
		(start 349.03156 -367.121948)
		(end 349.03156 -371.413278)
		(width 0.127)
		(layer "In6.Cu")
		(net "IRQ_PSYS_CRIT_N")
	)
	(segment
		(start 331.073252 -374.186196)
		(end 317.988696 -387.270752)
		(width 0.127)
		(layer "In6.Cu")
		(net "IRQ_PSYS_CRIT_N")
	)
	(segment
		(start 349.03156 -371.413278)
		(end 346.258642 -374.186196)
		(width 0.127)
		(layer "In6.Cu")
		(net "IRQ_PSYS_CRIT_N")
	)
	(segment
		(start 346.931234 -360.852974)
		(end 345.78798 -361.996228)
		(width 0.127)
		(layer "In6.Cu")
		(net "IRQ_PSYS_CRIT_N")
	)
	(segment
		(start 345.78798 -361.996228)
		(end 345.78798 -363.878368)
		(width 0.127)
		(layer "In6.Cu")
		(net "IRQ_PSYS_CRIT_N")
	)
	(segment
		(start 317.988696 -387.270752)
		(end 304.430684 -387.270752)
		(width 0.127)
		(layer "In6.Cu")
		(net "IRQ_PSYS_CRIT_N")
	)
	(segment
		(start 346.931234 -359.751122)
		(end 346.931234 -360.852974)
		(width 0.127)
		(layer "In6.Cu")
		(net "IRQ_PSYS_CRIT_N")
	)
	(segment
		(start 220.573346 -146.252946)
		(end 220.573346 -158.05912)
		(width 0.127)
		(layer "In11.Cu")
		(net "IRQ_PSYS_CRIT_N")
	)
	(segment
		(start 210.08848 -129.0193)
		(end 210.08848 -135.76808)
		(width 0.127)
		(layer "In11.Cu")
		(net "IRQ_PSYS_CRIT_N")
	)
	(segment
		(start 220.573346 -158.05912)
		(end 243.36248 -180.848254)
		(width 0.127)
		(layer "In11.Cu")
		(net "IRQ_PSYS_CRIT_N")
	)
	(segment
		(start 209.45348 -122.31624)
		(end 209.45348 -128.3843)
		(width 0.127)
		(layer "In11.Cu")
		(net "IRQ_PSYS_CRIT_N")
	)
	(segment
		(start 211.25688 -120.51284)
		(end 209.45348 -122.31624)
		(width 0.127)
		(layer "In11.Cu")
		(net "IRQ_PSYS_CRIT_N")
	)
	(segment
		(start 211.25688 -116.2558)
		(end 211.25688 -120.51284)
		(width 0.127)
		(layer "In11.Cu")
		(net "IRQ_PSYS_CRIT_N")
	)
	(segment
		(start 243.36248 -196.967348)
		(end 241.34826 -198.981568)
		(width 0.127)
		(layer "In11.Cu")
		(net "IRQ_PSYS_CRIT_N")
	)
	(segment
		(start 243.36248 -180.848254)
		(end 243.36248 -196.967348)
		(width 0.127)
		(layer "In11.Cu")
		(net "IRQ_PSYS_CRIT_N")
	)
	(segment
		(start 210.08848 -135.76808)
		(end 220.573346 -146.252946)
		(width 0.127)
		(layer "In11.Cu")
		(net "IRQ_PSYS_CRIT_N")
	)
	(segment
		(start 209.45348 -128.3843)
		(end 210.08848 -129.0193)
		(width 0.127)
		(layer "In11.Cu")
		(net "IRQ_PSYS_CRIT_N")
	)
	(segment
		(start 241.34826 -198.981568)
		(end 241.34826 -201.011028)
		(width 0.127)
		(layer "In11.Cu")
		(net "IRQ_PSYS_CRIT_N")
	)
	(segment
		(start 184.555638 -114.575336)
		(end 184.955688 -114.975386)
		(width 0.12954)
		(layer "F.Cu")
		(net "IRQ_PCH_SCI_WHEA_R_N")
	)
	(via
		(at 305.01082 -52.324508)
		(size 0.508)
		(drill 0.254)
		(layers "F.Cu" "B.Cu")
		(net "IRQ_PCH_SCI_WHEA_R_N")
	)
	(via
		(at 198.09968 -90.160348)
		(size 0.508)
		(drill 0.254)
		(layers "F.Cu" "B.Cu")
		(net "IRQ_PCH_SCI_WHEA_R_N")
	)
	(via
		(at 184.955688 -114.975386)
		(size 0.4572)
		(drill 0.254)
		(layers "F.Cu" "B.Cu")
		(net "IRQ_PCH_SCI_WHEA_R_N")
	)
	(via
		(at 195.25488 -116.804948)
		(size 0.762)
		(drill 0.254)
		(layers "F.Cu" "B.Cu")
		(net "IRQ_PCH_SCI_WHEA_R_N")
	)
	(via
		(at 243.84508 -67.274948)
		(size 0.508)
		(drill 0.254)
		(layers "F.Cu" "B.Cu")
		(net "IRQ_PCH_SCI_WHEA_R_N")
	)
	(segment
		(start 185.351166 -114.579908)
		(end 184.955688 -114.975386)
		(width 0.12954)
		(layer "B.Cu")
		(net "IRQ_PCH_SCI_WHEA_R_N")
	)
	(segment
		(start 309.99684 -52.014628)
		(end 309.99684 -50.681128)
		(width 0.12954)
		(layer "B.Cu")
		(net "IRQ_PCH_SCI_WHEA_R_N")
	)
	(segment
		(start 305.01082 -51.209448)
		(end 305.45278 -50.767488)
		(width 0.12954)
		(layer "B.Cu")
		(net "IRQ_PCH_SCI_WHEA_R_N")
	)
	(segment
		(start 306.42306 -50.767488)
		(end 308.41188 -52.756308)
		(width 0.12954)
		(layer "B.Cu")
		(net "IRQ_PCH_SCI_WHEA_R_N")
	)
	(segment
		(start 305.45278 -50.767488)
		(end 306.42306 -50.767488)
		(width 0.12954)
		(layer "B.Cu")
		(net "IRQ_PCH_SCI_WHEA_R_N")
	)
	(segment
		(start 309.25516 -52.756308)
		(end 309.99684 -52.014628)
		(width 0.12954)
		(layer "B.Cu")
		(net "IRQ_PCH_SCI_WHEA_R_N")
	)
	(segment
		(start 308.41188 -52.756308)
		(end 309.25516 -52.756308)
		(width 0.12954)
		(layer "B.Cu")
		(net "IRQ_PCH_SCI_WHEA_R_N")
	)
	(segment
		(start 310.45658 -50.221388)
		(end 311.15 -50.221388)
		(width 0.12954)
		(layer "B.Cu")
		(net "IRQ_PCH_SCI_WHEA_R_N")
	)
	(segment
		(start 195.25488 -116.804948)
		(end 194.68846 -116.238528)
		(width 0.12954)
		(layer "B.Cu")
		(net "IRQ_PCH_SCI_WHEA_R_N")
	)
	(segment
		(start 305.01082 -52.324508)
		(end 305.01082 -51.209448)
		(width 0.12954)
		(layer "B.Cu")
		(net "IRQ_PCH_SCI_WHEA_R_N")
	)
	(segment
		(start 188.975746 -116.238528)
		(end 187.317126 -114.579908)
		(width 0.12954)
		(layer "B.Cu")
		(net "IRQ_PCH_SCI_WHEA_R_N")
	)
	(segment
		(start 309.99684 -50.681128)
		(end 310.45658 -50.221388)
		(width 0.12954)
		(layer "B.Cu")
		(net "IRQ_PCH_SCI_WHEA_R_N")
	)
	(segment
		(start 311.15 -50.221388)
		(end 312.48096 -48.890428)
		(width 0.12954)
		(layer "B.Cu")
		(net "IRQ_PCH_SCI_WHEA_R_N")
	)
	(segment
		(start 194.68846 -116.238528)
		(end 188.975746 -116.238528)
		(width 0.12954)
		(layer "B.Cu")
		(net "IRQ_PCH_SCI_WHEA_R_N")
	)
	(segment
		(start 312.48096 -48.890428)
		(end 312.53049 -48.890428)
		(width 0.12954)
		(layer "B.Cu")
		(net "IRQ_PCH_SCI_WHEA_R_N")
	)
	(segment
		(start 187.317126 -114.579908)
		(end 185.351166 -114.579908)
		(width 0.12954)
		(layer "B.Cu")
		(net "IRQ_PCH_SCI_WHEA_R_N")
	)
	(segment
		(start 297.33748 -52.187348)
		(end 298.57446 -52.187348)
		(width 0.127)
		(layer "In6.Cu")
		(net "IRQ_PCH_SCI_WHEA_R_N")
	)
	(segment
		(start 304.53838 -52.796948)
		(end 305.01082 -52.324508)
		(width 0.127)
		(layer "In6.Cu")
		(net "IRQ_PCH_SCI_WHEA_R_N")
	)
	(segment
		(start 275.800312 -60.341764)
		(end 283.57703 -52.565046)
		(width 0.127)
		(layer "In6.Cu")
		(net "IRQ_PCH_SCI_WHEA_R_N")
	)
	(segment
		(start 296.959782 -52.565046)
		(end 297.33748 -52.187348)
		(width 0.127)
		(layer "In6.Cu")
		(net "IRQ_PCH_SCI_WHEA_R_N")
	)
	(segment
		(start 243.84508 -67.274948)
		(end 243.84508 -66.819018)
		(width 0.127)
		(layer "In6.Cu")
		(net "IRQ_PCH_SCI_WHEA_R_N")
	)
	(segment
		(start 300.5328 -52.796948)
		(end 304.53838 -52.796948)
		(width 0.127)
		(layer "In6.Cu")
		(net "IRQ_PCH_SCI_WHEA_R_N")
	)
	(segment
		(start 298.57446 -52.187348)
		(end 298.94022 -52.553108)
		(width 0.127)
		(layer "In6.Cu")
		(net "IRQ_PCH_SCI_WHEA_R_N")
	)
	(segment
		(start 266.12977 -61.559948)
		(end 273.360388 -61.559948)
		(width 0.127)
		(layer "In6.Cu")
		(net "IRQ_PCH_SCI_WHEA_R_N")
	)
	(segment
		(start 274.578572 -60.341764)
		(end 275.800312 -60.341764)
		(width 0.127)
		(layer "In6.Cu")
		(net "IRQ_PCH_SCI_WHEA_R_N")
	)
	(segment
		(start 245.09095 -65.573148)
		(end 259.978144 -65.573148)
		(width 0.127)
		(layer "In6.Cu")
		(net "IRQ_PCH_SCI_WHEA_R_N")
	)
	(segment
		(start 283.57703 -52.565046)
		(end 296.959782 -52.565046)
		(width 0.127)
		(layer "In6.Cu")
		(net "IRQ_PCH_SCI_WHEA_R_N")
	)
	(segment
		(start 273.360388 -61.559948)
		(end 274.578572 -60.341764)
		(width 0.127)
		(layer "In6.Cu")
		(net "IRQ_PCH_SCI_WHEA_R_N")
	)
	(segment
		(start 263.628632 -64.061086)
		(end 266.12977 -61.559948)
		(width 0.127)
		(layer "In6.Cu")
		(net "IRQ_PCH_SCI_WHEA_R_N")
	)
	(segment
		(start 243.84508 -66.819018)
		(end 245.09095 -65.573148)
		(width 0.127)
		(layer "In6.Cu")
		(net "IRQ_PCH_SCI_WHEA_R_N")
	)
	(segment
		(start 300.28896 -52.553108)
		(end 300.5328 -52.796948)
		(width 0.127)
		(layer "In6.Cu")
		(net "IRQ_PCH_SCI_WHEA_R_N")
	)
	(segment
		(start 298.94022 -52.553108)
		(end 300.28896 -52.553108)
		(width 0.127)
		(layer "In6.Cu")
		(net "IRQ_PCH_SCI_WHEA_R_N")
	)
	(segment
		(start 259.978144 -65.573148)
		(end 263.628632 -64.061086)
		(width 0.127)
		(layer "In6.Cu")
		(net "IRQ_PCH_SCI_WHEA_R_N")
	)
	(segment
		(start 198.09968 -90.160348)
		(end 198.09968 -90.893138)
		(width 0.127)
		(layer "In13.Cu")
		(net "IRQ_PCH_SCI_WHEA_R_N")
	)
	(segment
		(start 190.38824 -113.005108)
		(end 193.52768 -116.144548)
		(width 0.127)
		(layer "In13.Cu")
		(net "IRQ_PCH_SCI_WHEA_R_N")
	)
	(segment
		(start 193.52768 -116.144548)
		(end 194.59448 -116.144548)
		(width 0.127)
		(layer "In13.Cu")
		(net "IRQ_PCH_SCI_WHEA_R_N")
	)
	(segment
		(start 196.6214 -95.519494)
		(end 190.38824 -101.752654)
		(width 0.127)
		(layer "In13.Cu")
		(net "IRQ_PCH_SCI_WHEA_R_N")
	)
	(segment
		(start 194.59448 -116.144548)
		(end 195.25488 -116.804948)
		(width 0.127)
		(layer "In13.Cu")
		(net "IRQ_PCH_SCI_WHEA_R_N")
	)
	(segment
		(start 196.6214 -92.371418)
		(end 196.6214 -95.519494)
		(width 0.127)
		(layer "In13.Cu")
		(net "IRQ_PCH_SCI_WHEA_R_N")
	)
	(segment
		(start 190.38824 -101.752654)
		(end 190.38824 -113.005108)
		(width 0.127)
		(layer "In13.Cu")
		(net "IRQ_PCH_SCI_WHEA_R_N")
	)
	(segment
		(start 198.09968 -90.893138)
		(end 196.6214 -92.371418)
		(width 0.127)
		(layer "In13.Cu")
		(net "IRQ_PCH_SCI_WHEA_R_N")
	)
	(segment
		(start 221.84741 -80.406748)
		(end 200.56221 -80.406748)
		(width 0.127)
		(layer "In15.Cu")
		(net "IRQ_PCH_SCI_WHEA_R_N")
	)
	(segment
		(start 198.09968 -89.411048)
		(end 198.09968 -90.160348)
		(width 0.127)
		(layer "In15.Cu")
		(net "IRQ_PCH_SCI_WHEA_R_N")
	)
	(segment
		(start 233.368342 -68.885816)
		(end 221.84741 -80.406748)
		(width 0.127)
		(layer "In15.Cu")
		(net "IRQ_PCH_SCI_WHEA_R_N")
	)
	(segment
		(start 242.234212 -68.885816)
		(end 233.368342 -68.885816)
		(width 0.127)
		(layer "In15.Cu")
		(net "IRQ_PCH_SCI_WHEA_R_N")
	)
	(segment
		(start 200.56221 -80.406748)
		(end 198.30288 -82.666078)
		(width 0.127)
		(layer "In15.Cu")
		(net "IRQ_PCH_SCI_WHEA_R_N")
	)
	(segment
		(start 198.30288 -89.207848)
		(end 198.09968 -89.411048)
		(width 0.127)
		(layer "In15.Cu")
		(net "IRQ_PCH_SCI_WHEA_R_N")
	)
	(segment
		(start 198.30288 -82.666078)
		(end 198.30288 -89.207848)
		(width 0.127)
		(layer "In15.Cu")
		(net "IRQ_PCH_SCI_WHEA_R_N")
	)
	(segment
		(start 243.84508 -67.274948)
		(end 242.234212 -68.885816)
		(width 0.127)
		(layer "In15.Cu")
		(net "IRQ_PCH_SCI_WHEA_R_N")
	)
	(segment
		(start 319.324482 -50.510948)
		(end 318.841882 -50.028348)
		(width 0.12954)
		(layer "F.Cu")
		(net "IRQ_PCH_SCI_WHEA_N")
	)
	(segment
		(start 319.961768 -50.302668)
		(end 319.753488 -50.510948)
		(width 0.12954)
		(layer "F.Cu")
		(net "IRQ_PCH_SCI_WHEA_N")
	)
	(segment
		(start 325.391018 -49.450752)
		(end 324.939152 -49.902618)
		(width 0.0889)
		(layer "F.Cu")
		(net "IRQ_PCH_SCI_WHEA_N")
	)
	(segment
		(start 322.680076 -50.206148)
		(end 321.59956 -50.206148)
		(width 0.12954)
		(layer "F.Cu")
		(net "IRQ_PCH_SCI_WHEA_N")
	)
	(segment
		(start 321.59956 -50.206148)
		(end 321.50304 -50.302668)
		(width 0.12954)
		(layer "F.Cu")
		(net "IRQ_PCH_SCI_WHEA_N")
	)
	(segment
		(start 322.983606 -49.902618)
		(end 322.680076 -50.206148)
		(width 0.0889)
		(layer "F.Cu")
		(net "IRQ_PCH_SCI_WHEA_N")
	)
	(segment
		(start 326.999854 -49.450752)
		(end 325.391018 -49.450752)
		(width 0.0889)
		(layer "F.Cu")
		(net "IRQ_PCH_SCI_WHEA_N")
	)
	(segment
		(start 315.637672 -50.028348)
		(end 315.510672 -50.155348)
		(width 0.12954)
		(layer "F.Cu")
		(net "IRQ_PCH_SCI_WHEA_N")
	)
	(segment
		(start 312.34888 -50.114708)
		(end 312.86704 -50.632868)
		(width 0.12954)
		(layer "F.Cu")
		(net "IRQ_PCH_SCI_WHEA_N")
	)
	(segment
		(start 319.753488 -50.510948)
		(end 319.324482 -50.510948)
		(width 0.12954)
		(layer "F.Cu")
		(net "IRQ_PCH_SCI_WHEA_N")
	)
	(segment
		(start 312.86704 -50.632868)
		(end 315.033152 -50.632868)
		(width 0.12954)
		(layer "F.Cu")
		(net "IRQ_PCH_SCI_WHEA_N")
	)
	(segment
		(start 315.033152 -50.632868)
		(end 315.510672 -50.155348)
		(width 0.12954)
		(layer "F.Cu")
		(net "IRQ_PCH_SCI_WHEA_N")
	)
	(segment
		(start 324.939152 -49.902618)
		(end 322.983606 -49.902618)
		(width 0.0889)
		(layer "F.Cu")
		(net "IRQ_PCH_SCI_WHEA_N")
	)
	(segment
		(start 318.841882 -50.028348)
		(end 315.637672 -50.028348)
		(width 0.12954)
		(layer "F.Cu")
		(net "IRQ_PCH_SCI_WHEA_N")
	)
	(segment
		(start 321.50304 -50.302668)
		(end 319.961768 -50.302668)
		(width 0.12954)
		(layer "F.Cu")
		(net "IRQ_PCH_SCI_WHEA_N")
	)
	(via
		(at 312.34888 -50.114708)
		(size 0.762)
		(drill 0.254)
		(layers "F.Cu" "B.Cu")
		(net "IRQ_PCH_SCI_WHEA_N")
	)
	(segment
		(start 312.34888 -50.114708)
		(end 313.33059 -49.132998)
		(width 0.12954)
		(layer "B.Cu")
		(net "IRQ_PCH_SCI_WHEA_N")
	)
	(segment
		(start 313.33059 -49.132998)
		(end 313.33059 -48.890428)
		(width 0.12954)
		(layer "B.Cu")
		(net "IRQ_PCH_SCI_WHEA_N")
	)
	(segment
		(start 333.23657 -43.751246)
		(end 332.697328 -43.751246)
		(width 0.12954)
		(layer "F.Cu")
		(net "IRQ_PCH_CPU_NMI_EVENT_R_N")
	)
	(via
		(at 329.662536 -30.498288)
		(size 0.6604)
		(drill 0.3302)
		(layers "F.Cu" "B.Cu")
		(net "IRQ_PCH_CPU_NMI_EVENT_R_N")
	)
	(via
		(at 332.697328 -43.751246)
		(size 0.4572)
		(drill 0.2032)
		(layers "F.Cu" "B.Cu")
		(net "IRQ_PCH_CPU_NMI_EVENT_R_N")
	)
	(segment
		(start 329.912218 -40.618156)
		(end 329.860656 -40.486584)
		(width 0.0889)
		(layer "B.Cu")
		(net "IRQ_PCH_CPU_NMI_EVENT_R_N")
	)
	(segment
		(start 329.4634 -36.072826)
		(end 329.4634 -34.807906)
		(width 0.12954)
		(layer "B.Cu")
		(net "IRQ_PCH_CPU_NMI_EVENT_R_N")
	)
	(segment
		(start 331.068426 -41.496996)
		(end 331.067664 -41.496996)
		(width 0.0889)
		(layer "B.Cu")
		(net "IRQ_PCH_CPU_NMI_EVENT_R_N")
	)
	(segment
		(start 330.40574 -26.162508)
		(end 329.646534 -25.403302)
		(width 0.12954)
		(layer "B.Cu")
		(net "IRQ_PCH_CPU_NMI_EVENT_R_N")
	)
	(segment
		(start 330.466954 -41.018968)
		(end 330.28001 -40.879014)
		(width 0.0889)
		(layer "B.Cu")
		(net "IRQ_PCH_CPU_NMI_EVENT_R_N")
	)
	(segment
		(start 330.024994 -40.776398)
		(end 329.953366 -40.690038)
		(width 0.0889)
		(layer "B.Cu")
		(net "IRQ_PCH_CPU_NMI_EVENT_R_N")
	)
	(segment
		(start 330.28001 -40.879014)
		(end 330.10094 -40.827706)
		(width 0.0889)
		(layer "B.Cu")
		(net "IRQ_PCH_CPU_NMI_EVENT_R_N")
	)
	(segment
		(start 329.459844 -39.06774)
		(end 329.459844 -37.672772)
		(width 0.12954)
		(layer "B.Cu")
		(net "IRQ_PCH_CPU_NMI_EVENT_R_N")
	)
	(segment
		(start 331.889862 -42.906696)
		(end 331.881988 -42.906696)
		(width 0.0889)
		(layer "B.Cu")
		(net "IRQ_PCH_CPU_NMI_EVENT_R_N")
	)
	(segment
		(start 329.4634 -34.807906)
		(end 329.629262 -34.642044)
		(width 0.12954)
		(layer "B.Cu")
		(net "IRQ_PCH_CPU_NMI_EVENT_R_N")
	)
	(segment
		(start 329.953366 -40.690038)
		(end 329.912218 -40.618156)
		(width 0.0889)
		(layer "B.Cu")
		(net "IRQ_PCH_CPU_NMI_EVENT_R_N")
	)
	(segment
		(start 328.891138 -25.403302)
		(end 329.646534 -25.403302)
		(width 0.12954)
		(layer "B.Cu")
		(net "IRQ_PCH_CPU_NMI_EVENT_R_N")
	)
	(segment
		(start 330.40574 -28.484068)
		(end 330.40574 -26.162508)
		(width 0.12954)
		(layer "B.Cu")
		(net "IRQ_PCH_CPU_NMI_EVENT_R_N")
	)
	(segment
		(start 331.392276 -42.058844)
		(end 331.401166 -42.04335)
		(width 0.0889)
		(layer "B.Cu")
		(net "IRQ_PCH_CPU_NMI_EVENT_R_N")
	)
	(segment
		(start 328.092816 -26.201624)
		(end 328.891138 -25.403302)
		(width 0.12954)
		(layer "B.Cu")
		(net "IRQ_PCH_CPU_NMI_EVENT_R_N")
	)
	(segment
		(start 329.108054 -37.320982)
		(end 329.108054 -36.930838)
		(width 0.12954)
		(layer "B.Cu")
		(net "IRQ_PCH_CPU_NMI_EVENT_R_N")
	)
	(segment
		(start 329.842368 -40.013636)
		(end 329.76058 -39.756588)
		(width 0.0889)
		(layer "B.Cu")
		(net "IRQ_PCH_CPU_NMI_EVENT_R_N")
	)
	(segment
		(start 329.76058 -39.756588)
		(end 329.756008 -39.74211)
		(width 0.0889)
		(layer "B.Cu")
		(net "IRQ_PCH_CPU_NMI_EVENT_R_N")
	)
	(segment
		(start 329.860656 -40.486584)
		(end 329.842368 -40.013636)
		(width 0.0889)
		(layer "B.Cu")
		(net "IRQ_PCH_CPU_NMI_EVENT_R_N")
	)
	(segment
		(start 329.459844 -37.672772)
		(end 329.108054 -37.320982)
		(width 0.12954)
		(layer "B.Cu")
		(net "IRQ_PCH_CPU_NMI_EVENT_R_N")
	)
	(segment
		(start 329.756008 -39.74211)
		(end 329.459844 -39.06774)
		(width 0.0889)
		(layer "B.Cu")
		(net "IRQ_PCH_CPU_NMI_EVENT_R_N")
	)
	(segment
		(start 332.224126 -43.123358)
		(end 332.207616 -43.094148)
		(width 0.0889)
		(layer "B.Cu")
		(net "IRQ_PCH_CPU_NMI_EVENT_R_N")
	)
	(segment
		(start 329.662536 -29.227272)
		(end 330.40574 -28.484068)
		(width 0.12954)
		(layer "B.Cu")
		(net "IRQ_PCH_CPU_NMI_EVENT_R_N")
	)
	(segment
		(start 330.57846 -41.214548)
		(end 330.466954 -41.018968)
		(width 0.0889)
		(layer "B.Cu")
		(net "IRQ_PCH_CPU_NMI_EVENT_R_N")
	)
	(segment
		(start 330.10094 -40.827706)
		(end 330.024994 -40.776398)
		(width 0.0889)
		(layer "B.Cu")
		(net "IRQ_PCH_CPU_NMI_EVENT_R_N")
	)
	(segment
		(start 329.662536 -30.498288)
		(end 329.662536 -29.227272)
		(width 0.12954)
		(layer "B.Cu")
		(net "IRQ_PCH_CPU_NMI_EVENT_R_N")
	)
	(segment
		(start 329.629262 -30.762702)
		(end 329.662536 -30.729428)
		(width 0.12954)
		(layer "B.Cu")
		(net "IRQ_PCH_CPU_NMI_EVENT_R_N")
	)
	(segment
		(start 329.108054 -36.930838)
		(end 329.4634 -36.072826)
		(width 0.12954)
		(layer "B.Cu")
		(net "IRQ_PCH_CPU_NMI_EVENT_R_N")
	)
	(segment
		(start 329.662536 -30.729428)
		(end 329.662536 -30.498288)
		(width 0.12954)
		(layer "B.Cu")
		(net "IRQ_PCH_CPU_NMI_EVENT_R_N")
	)
	(segment
		(start 332.697328 -43.751246)
		(end 332.224126 -43.123358)
		(width 0.0889)
		(layer "B.Cu")
		(net "IRQ_PCH_CPU_NMI_EVENT_R_N")
	)
	(segment
		(start 329.629262 -34.642044)
		(end 329.629262 -30.762702)
		(width 0.12954)
		(layer "B.Cu")
		(net "IRQ_PCH_CPU_NMI_EVENT_R_N")
	)
	(arc
		(start 331.401166 -42.04335)
		(mid 331.442697 -41.862839)
		(end 331.392784 -41.684448)
		(width 0.0889)
		(layer "B.Cu")
		(net "IRQ_PCH_CPU_NMI_EVENT_R_N")
	)
	(arc
		(start 332.207616 -43.094148)
		(mid 332.073407 -42.958604)
		(end 331.889862 -42.906696)
		(width 0.0889)
		(layer "B.Cu")
		(net "IRQ_PCH_CPU_NMI_EVENT_R_N")
	)
	(arc
		(start 331.067664 -41.496996)
		(mid 330.785218 -41.421316)
		(end 330.57846 -41.214548)
		(width 0.0889)
		(layer "B.Cu")
		(net "IRQ_PCH_CPU_NMI_EVENT_R_N")
	)
	(arc
		(start 331.392784 -41.684448)
		(mid 331.255735 -41.547244)
		(end 331.068426 -41.496996)
		(width 0.0889)
		(layer "B.Cu")
		(net "IRQ_PCH_CPU_NMI_EVENT_R_N")
	)
	(arc
		(start 331.392276 -42.624248)
		(mid 331.316534 -42.341546)
		(end 331.392276 -42.058844)
		(width 0.0889)
		(layer "B.Cu")
		(net "IRQ_PCH_CPU_NMI_EVENT_R_N")
	)
	(arc
		(start 331.881988 -42.906696)
		(mid 331.599286 -42.831122)
		(end 331.392276 -42.624248)
		(width 0.0889)
		(layer "B.Cu")
		(net "IRQ_PCH_CPU_NMI_EVENT_R_N")
	)
	(segment
		(start 183.755538 -114.575336)
		(end 184.155588 -114.975386)
		(width 0.12954)
		(layer "F.Cu")
		(net "IRQ_PCH_CPU_NMI_EVENT_N")
	)
	(via
		(at 327.96988 -117.693948)
		(size 0.508)
		(drill 0.254)
		(layers "F.Cu" "B.Cu")
		(net "IRQ_PCH_CPU_NMI_EVENT_N")
	)
	(via
		(at 184.155588 -114.975386)
		(size 0.4572)
		(drill 0.254)
		(layers "F.Cu" "B.Cu")
		(net "IRQ_PCH_CPU_NMI_EVENT_N")
	)
	(via
		(at 328.765916 -26.204164)
		(size 0.508)
		(drill 0.254)
		(layers "F.Cu" "B.Cu")
		(net "IRQ_PCH_CPU_NMI_EVENT_N")
	)
	(segment
		(start 328.766678 -26.203402)
		(end 329.646534 -26.203402)
		(width 0.12954)
		(layer "B.Cu")
		(net "IRQ_PCH_CPU_NMI_EVENT_N")
	)
	(segment
		(start 328.765916 -26.204164)
		(end 328.766678 -26.203402)
		(width 0.12954)
		(layer "B.Cu")
		(net "IRQ_PCH_CPU_NMI_EVENT_N")
	)
	(segment
		(start 327.152 -116.876068)
		(end 327.152 -73.282048)
		(width 0.127)
		(layer "In2.Cu")
		(net "IRQ_PCH_CPU_NMI_EVENT_N")
	)
	(segment
		(start 330.327 -36.058348)
		(end 329.9714 -35.702748)
		(width 0.127)
		(layer "In2.Cu")
		(net "IRQ_PCH_CPU_NMI_EVENT_N")
	)
	(segment
		(start 329.9714 -27.409648)
		(end 328.765916 -26.204164)
		(width 0.127)
		(layer "In2.Cu")
		(net "IRQ_PCH_CPU_NMI_EVENT_N")
	)
	(segment
		(start 329.1459 -71.288148)
		(end 329.1459 -59.878468)
		(width 0.127)
		(layer "In2.Cu")
		(net "IRQ_PCH_CPU_NMI_EVENT_N")
	)
	(segment
		(start 327.152 -73.282048)
		(end 329.1459 -71.288148)
		(width 0.127)
		(layer "In2.Cu")
		(net "IRQ_PCH_CPU_NMI_EVENT_N")
	)
	(segment
		(start 327.68286 -39.718488)
		(end 330.327 -37.074348)
		(width 0.127)
		(layer "In2.Cu")
		(net "IRQ_PCH_CPU_NMI_EVENT_N")
	)
	(segment
		(start 327.96988 -117.693948)
		(end 327.152 -116.876068)
		(width 0.127)
		(layer "In2.Cu")
		(net "IRQ_PCH_CPU_NMI_EVENT_N")
	)
	(segment
		(start 327.68286 -58.415428)
		(end 327.68286 -39.718488)
		(width 0.127)
		(layer "In2.Cu")
		(net "IRQ_PCH_CPU_NMI_EVENT_N")
	)
	(segment
		(start 330.327 -37.074348)
		(end 330.327 -36.058348)
		(width 0.127)
		(layer "In2.Cu")
		(net "IRQ_PCH_CPU_NMI_EVENT_N")
	)
	(segment
		(start 329.9714 -35.702748)
		(end 329.9714 -27.409648)
		(width 0.127)
		(layer "In2.Cu")
		(net "IRQ_PCH_CPU_NMI_EVENT_N")
	)
	(segment
		(start 329.1459 -59.878468)
		(end 327.68286 -58.415428)
		(width 0.127)
		(layer "In2.Cu")
		(net "IRQ_PCH_CPU_NMI_EVENT_N")
	)
	(segment
		(start 199.8472 -116.253768)
		(end 206.629 -116.253768)
		(width 0.127)
		(layer "In15.Cu")
		(net "IRQ_PCH_CPU_NMI_EVENT_N")
	)
	(segment
		(start 221.72168 -113.055908)
		(end 233.491532 -113.055908)
		(width 0.127)
		(layer "In15.Cu")
		(net "IRQ_PCH_CPU_NMI_EVENT_N")
	)
	(segment
		(start 238.9505 -114.351308)
		(end 239.71504 -115.115848)
		(width 0.127)
		(layer "In15.Cu")
		(net "IRQ_PCH_CPU_NMI_EVENT_N")
	)
	(segment
		(start 318.34328 -116.398548)
		(end 319.84188 -114.899948)
		(width 0.127)
		(layer "In15.Cu")
		(net "IRQ_PCH_CPU_NMI_EVENT_N")
	)
	(segment
		(start 198.82612 -117.274848)
		(end 199.8472 -116.253768)
		(width 0.127)
		(layer "In15.Cu")
		(net "IRQ_PCH_CPU_NMI_EVENT_N")
	)
	(segment
		(start 184.561226 -114.569748)
		(end 190.60668 -114.569748)
		(width 0.127)
		(layer "In15.Cu")
		(net "IRQ_PCH_CPU_NMI_EVENT_N")
	)
	(segment
		(start 283.44876 -116.398548)
		(end 318.34328 -116.398548)
		(width 0.127)
		(layer "In15.Cu")
		(net "IRQ_PCH_CPU_NMI_EVENT_N")
	)
	(segment
		(start 245.65991 -115.115848)
		(end 249.54611 -119.002048)
		(width 0.127)
		(layer "In15.Cu")
		(net "IRQ_PCH_CPU_NMI_EVENT_N")
	)
	(segment
		(start 220.42628 -114.351308)
		(end 221.72168 -113.055908)
		(width 0.127)
		(layer "In15.Cu")
		(net "IRQ_PCH_CPU_NMI_EVENT_N")
	)
	(segment
		(start 190.60668 -114.569748)
		(end 191.97828 -115.941348)
		(width 0.127)
		(layer "In15.Cu")
		(net "IRQ_PCH_CPU_NMI_EVENT_N")
	)
	(segment
		(start 191.97828 -115.941348)
		(end 192.28308 -115.941348)
		(width 0.127)
		(layer "In15.Cu")
		(net "IRQ_PCH_CPU_NMI_EVENT_N")
	)
	(segment
		(start 322.00088 -116.296948)
		(end 326.57288 -116.296948)
		(width 0.127)
		(layer "In15.Cu")
		(net "IRQ_PCH_CPU_NMI_EVENT_N")
	)
	(segment
		(start 233.491532 -113.055908)
		(end 234.786932 -114.351308)
		(width 0.127)
		(layer "In15.Cu")
		(net "IRQ_PCH_CPU_NMI_EVENT_N")
	)
	(segment
		(start 320.60388 -114.899948)
		(end 322.00088 -116.296948)
		(width 0.127)
		(layer "In15.Cu")
		(net "IRQ_PCH_CPU_NMI_EVENT_N")
	)
	(segment
		(start 206.629 -116.253768)
		(end 207.160368 -115.7224)
		(width 0.127)
		(layer "In15.Cu")
		(net "IRQ_PCH_CPU_NMI_EVENT_N")
	)
	(segment
		(start 213.9061 -114.351308)
		(end 220.42628 -114.351308)
		(width 0.127)
		(layer "In15.Cu")
		(net "IRQ_PCH_CPU_NMI_EVENT_N")
	)
	(segment
		(start 197.12178 -117.274848)
		(end 198.82612 -117.274848)
		(width 0.127)
		(layer "In15.Cu")
		(net "IRQ_PCH_CPU_NMI_EVENT_N")
	)
	(segment
		(start 249.54611 -119.002048)
		(end 268.180566 -119.002048)
		(width 0.127)
		(layer "In15.Cu")
		(net "IRQ_PCH_CPU_NMI_EVENT_N")
	)
	(segment
		(start 184.155588 -114.975386)
		(end 184.561226 -114.569748)
		(width 0.127)
		(layer "In15.Cu")
		(net "IRQ_PCH_CPU_NMI_EVENT_N")
	)
	(segment
		(start 282.53436 -117.312948)
		(end 283.44876 -116.398548)
		(width 0.127)
		(layer "In15.Cu")
		(net "IRQ_PCH_CPU_NMI_EVENT_N")
	)
	(segment
		(start 192.28308 -115.941348)
		(end 193.87058 -117.528848)
		(width 0.127)
		(layer "In15.Cu")
		(net "IRQ_PCH_CPU_NMI_EVENT_N")
	)
	(segment
		(start 319.84188 -114.899948)
		(end 320.60388 -114.899948)
		(width 0.127)
		(layer "In15.Cu")
		(net "IRQ_PCH_CPU_NMI_EVENT_N")
	)
	(segment
		(start 326.57288 -116.296948)
		(end 327.96988 -117.693948)
		(width 0.127)
		(layer "In15.Cu")
		(net "IRQ_PCH_CPU_NMI_EVENT_N")
	)
	(segment
		(start 234.786932 -114.351308)
		(end 238.9505 -114.351308)
		(width 0.127)
		(layer "In15.Cu")
		(net "IRQ_PCH_CPU_NMI_EVENT_N")
	)
	(segment
		(start 212.535008 -115.7224)
		(end 213.9061 -114.351308)
		(width 0.127)
		(layer "In15.Cu")
		(net "IRQ_PCH_CPU_NMI_EVENT_N")
	)
	(segment
		(start 268.180566 -119.002048)
		(end 269.869666 -117.312948)
		(width 0.127)
		(layer "In15.Cu")
		(net "IRQ_PCH_CPU_NMI_EVENT_N")
	)
	(segment
		(start 269.869666 -117.312948)
		(end 282.53436 -117.312948)
		(width 0.127)
		(layer "In15.Cu")
		(net "IRQ_PCH_CPU_NMI_EVENT_N")
	)
	(segment
		(start 196.86778 -117.528848)
		(end 197.12178 -117.274848)
		(width 0.127)
		(layer "In15.Cu")
		(net "IRQ_PCH_CPU_NMI_EVENT_N")
	)
	(segment
		(start 207.160368 -115.7224)
		(end 212.535008 -115.7224)
		(width 0.127)
		(layer "In15.Cu")
		(net "IRQ_PCH_CPU_NMI_EVENT_N")
	)
	(segment
		(start 239.71504 -115.115848)
		(end 245.65991 -115.115848)
		(width 0.127)
		(layer "In15.Cu")
		(net "IRQ_PCH_CPU_NMI_EVENT_N")
	)
	(segment
		(start 193.87058 -117.528848)
		(end 196.86778 -117.528848)
		(width 0.127)
		(layer "In15.Cu")
		(net "IRQ_PCH_CPU_NMI_EVENT_N")
	)
	(segment
		(start 160.40608 -12.586208)
		(end 160.40608 -19.327368)
		(width 0.12954)
		(layer "F.Cu")
		(net "IRQ_LVC3_WAKE_N")
	)
	(segment
		(start 160.40608 -19.327368)
		(end 159.939736 -19.793712)
		(width 0.12954)
		(layer "F.Cu")
		(net "IRQ_LVC3_WAKE_N")
	)
	(segment
		(start 165.30828 -39.925498)
		(end 164.12083 -41.112948)
		(width 0.12954)
		(layer "F.Cu")
		(net "IRQ_LVC3_WAKE_N")
	)
	(segment
		(start 331.880718 -47.040546)
		(end 331.749146 -47.040546)
		(width 0.12954)
		(layer "F.Cu")
		(net "IRQ_LVC3_WAKE_N")
	)
	(segment
		(start 305.837336 -15.535148)
		(end 305.863244 -15.50924)
		(width 0.12954)
		(layer "F.Cu")
		(net "IRQ_LVC3_WAKE_N")
	)
	(segment
		(start 304.65268 -15.535148)
		(end 305.837336 -15.535148)
		(width 0.12954)
		(layer "F.Cu")
		(net "IRQ_LVC3_WAKE_N")
	)
	(segment
		(start 159.41548 -21.407628)
		(end 159.41548 -27.046428)
		(width 0.12954)
		(layer "F.Cu")
		(net "IRQ_LVC3_WAKE_N")
	)
	(segment
		(start 166.1287 -38.021768)
		(end 165.30828 -38.842188)
		(width 0.12954)
		(layer "F.Cu")
		(net "IRQ_LVC3_WAKE_N")
	)
	(segment
		(start 159.23768 -10.683748)
		(end 159.23768 -11.417808)
		(width 0.12954)
		(layer "F.Cu")
		(net "IRQ_LVC3_WAKE_N")
	)
	(segment
		(start 331.749146 -47.040546)
		(end 331.608176 -46.899576)
		(width 0.12954)
		(layer "F.Cu")
		(net "IRQ_LVC3_WAKE_N")
	)
	(segment
		(start 304.17008 -15.052548)
		(end 304.65268 -15.535148)
		(width 0.12954)
		(layer "F.Cu")
		(net "IRQ_LVC3_WAKE_N")
	)
	(segment
		(start 159.939736 -19.793712)
		(end 159.939736 -20.883372)
		(width 0.12954)
		(layer "F.Cu")
		(net "IRQ_LVC3_WAKE_N")
	)
	(segment
		(start 159.23768 -11.417808)
		(end 160.40608 -12.586208)
		(width 0.12954)
		(layer "F.Cu")
		(net "IRQ_LVC3_WAKE_N")
	)
	(segment
		(start 160.58388 -9.845548)
		(end 160.07588 -9.845548)
		(width 0.12954)
		(layer "F.Cu")
		(net "IRQ_LVC3_WAKE_N")
	)
	(segment
		(start 161.85388 -8.575548)
		(end 160.58388 -9.845548)
		(width 0.12954)
		(layer "F.Cu")
		(net "IRQ_LVC3_WAKE_N")
	)
	(segment
		(start 331.608176 -46.899576)
		(end 331.608176 -46.570646)
		(width 0.12954)
		(layer "F.Cu")
		(net "IRQ_LVC3_WAKE_N")
	)
	(segment
		(start 304.17008 -14.468348)
		(end 304.17008 -15.052548)
		(width 0.12954)
		(layer "F.Cu")
		(net "IRQ_LVC3_WAKE_N")
	)
	(segment
		(start 166.1287 -33.759648)
		(end 166.1287 -38.021768)
		(width 0.12954)
		(layer "F.Cu")
		(net "IRQ_LVC3_WAKE_N")
	)
	(segment
		(start 281.230578 -14.09827)
		(end 282.188158 -14.09827)
		(width 0.12954)
		(layer "F.Cu")
		(net "IRQ_LVC3_WAKE_N")
	)
	(segment
		(start 161.85388 -7.991348)
		(end 161.85388 -8.575548)
		(width 0.12954)
		(layer "F.Cu")
		(net "IRQ_LVC3_WAKE_N")
	)
	(segment
		(start 165.30828 -38.842188)
		(end 165.30828 -39.925498)
		(width 0.12954)
		(layer "F.Cu")
		(net "IRQ_LVC3_WAKE_N")
	)
	(segment
		(start 160.07588 -9.845548)
		(end 159.23768 -10.683748)
		(width 0.12954)
		(layer "F.Cu")
		(net "IRQ_LVC3_WAKE_N")
	)
	(segment
		(start 159.41548 -27.046428)
		(end 166.1287 -33.759648)
		(width 0.12954)
		(layer "F.Cu")
		(net "IRQ_LVC3_WAKE_N")
	)
	(segment
		(start 159.939736 -20.883372)
		(end 159.41548 -21.407628)
		(width 0.12954)
		(layer "F.Cu")
		(net "IRQ_LVC3_WAKE_N")
	)
	(via
		(at 304.17008 -14.468348)
		(size 0.508)
		(drill 0.254)
		(layers "F.Cu" "B.Cu")
		(net "IRQ_LVC3_WAKE_N")
	)
	(via
		(at 159.939736 -19.793712)
		(size 0.762)
		(drill 0.381)
		(layers "F.Cu" "B.Cu")
		(net "IRQ_LVC3_WAKE_N")
	)
	(via
		(at 282.188158 -14.09827)
		(size 0.508)
		(drill 0.254)
		(layers "F.Cu" "B.Cu")
		(net "IRQ_LVC3_WAKE_N")
	)
	(via
		(at 161.85388 -7.991348)
		(size 0.508)
		(drill 0.254)
		(layers "F.Cu" "B.Cu")
		(net "IRQ_LVC3_WAKE_N")
	)
	(via
		(at 313.625484 -34.55416)
		(size 0.508)
		(drill 0.254)
		(layers "F.Cu" "B.Cu")
		(net "IRQ_LVC3_WAKE_N")
	)
	(via
		(at 331.880718 -47.040546)
		(size 0.4572)
		(drill 0.2032)
		(layers "F.Cu" "B.Cu")
		(net "IRQ_LVC3_WAKE_N")
	)
	(segment
		(start 330.85405 -47.040546)
		(end 330.405232 -47.489364)
		(width 0.0889)
		(layer "B.Cu")
		(net "IRQ_LVC3_WAKE_N")
	)
	(segment
		(start 313.625484 -36.22421)
		(end 313.625484 -34.55416)
		(width 0.12954)
		(layer "B.Cu")
		(net "IRQ_LVC3_WAKE_N")
	)
	(segment
		(start 327.676256 -46.663864)
		(end 327.368154 -46.355762)
		(width 0.12954)
		(layer "B.Cu")
		(net "IRQ_LVC3_WAKE_N")
	)
	(segment
		(start 325.027544 -46.293278)
		(end 324.804532 -46.293278)
		(width 0.12954)
		(layer "B.Cu")
		(net "IRQ_LVC3_WAKE_N")
	)
	(segment
		(start 331.880718 -47.040546)
		(end 330.85405 -47.040546)
		(width 0.0889)
		(layer "B.Cu")
		(net "IRQ_LVC3_WAKE_N")
	)
	(segment
		(start 325.308214 -46.573948)
		(end 325.027544 -46.293278)
		(width 0.12954)
		(layer "B.Cu")
		(net "IRQ_LVC3_WAKE_N")
	)
	(segment
		(start 314.0202 -38.197028)
		(end 314.0202 -36.618926)
		(width 0.12954)
		(layer "B.Cu")
		(net "IRQ_LVC3_WAKE_N")
	)
	(segment
		(start 322.512944 -44.00169)
		(end 322.061078 -44.00169)
		(width 0.12954)
		(layer "B.Cu")
		(net "IRQ_LVC3_WAKE_N")
	)
	(segment
		(start 330.17206 -47.489364)
		(end 329.722226 -47.03953)
		(width 0.0889)
		(layer "B.Cu")
		(net "IRQ_LVC3_WAKE_N")
	)
	(segment
		(start 329.722226 -47.03953)
		(end 328.980038 -47.03953)
		(width 0.0889)
		(layer "B.Cu")
		(net "IRQ_LVC3_WAKE_N")
	)
	(segment
		(start 328.149712 -46.663864)
		(end 327.981056 -46.663864)
		(width 0.0889)
		(layer "B.Cu")
		(net "IRQ_LVC3_WAKE_N")
	)
	(segment
		(start 326.543416 -46.355762)
		(end 326.32523 -46.573948)
		(width 0.12954)
		(layer "B.Cu")
		(net "IRQ_LVC3_WAKE_N")
	)
	(segment
		(start 324.804532 -46.293278)
		(end 322.512944 -44.00169)
		(width 0.12954)
		(layer "B.Cu")
		(net "IRQ_LVC3_WAKE_N")
	)
	(segment
		(start 319.31356 -43.490388)
		(end 314.0202 -38.197028)
		(width 0.12954)
		(layer "B.Cu")
		(net "IRQ_LVC3_WAKE_N")
	)
	(segment
		(start 313.173872 -34.102548)
		(end 312.843672 -34.102548)
		(width 0.12954)
		(layer "B.Cu")
		(net "IRQ_LVC3_WAKE_N")
	)
	(segment
		(start 326.32523 -46.573948)
		(end 325.308214 -46.573948)
		(width 0.12954)
		(layer "B.Cu")
		(net "IRQ_LVC3_WAKE_N")
	)
	(segment
		(start 328.980038 -47.03953)
		(end 328.885296 -46.944788)
		(width 0.0889)
		(layer "B.Cu")
		(net "IRQ_LVC3_WAKE_N")
	)
	(segment
		(start 313.625484 -34.55416)
		(end 313.173872 -34.102548)
		(width 0.12954)
		(layer "B.Cu")
		(net "IRQ_LVC3_WAKE_N")
	)
	(segment
		(start 327.981056 -46.663864)
		(end 327.676256 -46.663864)
		(width 0.12954)
		(layer "B.Cu")
		(net "IRQ_LVC3_WAKE_N")
	)
	(segment
		(start 328.430636 -46.944788)
		(end 328.149712 -46.663864)
		(width 0.0889)
		(layer "B.Cu")
		(net "IRQ_LVC3_WAKE_N")
	)
	(segment
		(start 322.061078 -44.00169)
		(end 321.549776 -43.490388)
		(width 0.12954)
		(layer "B.Cu")
		(net "IRQ_LVC3_WAKE_N")
	)
	(segment
		(start 328.885296 -46.944788)
		(end 328.430636 -46.944788)
		(width 0.0889)
		(layer "B.Cu")
		(net "IRQ_LVC3_WAKE_N")
	)
	(segment
		(start 321.549776 -43.490388)
		(end 319.31356 -43.490388)
		(width 0.12954)
		(layer "B.Cu")
		(net "IRQ_LVC3_WAKE_N")
	)
	(segment
		(start 327.368154 -46.355762)
		(end 326.543416 -46.355762)
		(width 0.12954)
		(layer "B.Cu")
		(net "IRQ_LVC3_WAKE_N")
	)
	(segment
		(start 330.405232 -47.489364)
		(end 330.17206 -47.489364)
		(width 0.0889)
		(layer "B.Cu")
		(net "IRQ_LVC3_WAKE_N")
	)
	(segment
		(start 314.0202 -36.618926)
		(end 313.625484 -36.22421)
		(width 0.12954)
		(layer "B.Cu")
		(net "IRQ_LVC3_WAKE_N")
	)
	(segment
		(start 304.17008 -15.027148)
		(end 304.17008 -14.468348)
		(width 0.127)
		(layer "In2.Cu")
		(net "IRQ_LVC3_WAKE_N")
	)
	(segment
		(start 313.625484 -23.187152)
		(end 305.94808 -15.509748)
		(width 0.127)
		(layer "In2.Cu")
		(net "IRQ_LVC3_WAKE_N")
	)
	(segment
		(start 305.94808 -15.509748)
		(end 304.65268 -15.509748)
		(width 0.127)
		(layer "In2.Cu")
		(net "IRQ_LVC3_WAKE_N")
	)
	(segment
		(start 313.625484 -34.55416)
		(end 313.625484 -23.187152)
		(width 0.127)
		(layer "In2.Cu")
		(net "IRQ_LVC3_WAKE_N")
	)
	(segment
		(start 304.65268 -15.509748)
		(end 304.17008 -15.027148)
		(width 0.127)
		(layer "In2.Cu")
		(net "IRQ_LVC3_WAKE_N")
	)
	(segment
		(start 275.558758 -14.09827)
		(end 282.188158 -14.09827)
		(width 0.127)
		(layer "In4.Cu")
		(net "IRQ_LVC3_WAKE_N")
	)
	(segment
		(start 268.02588 -29.555948)
		(end 272.80108 -24.780748)
		(width 0.127)
		(layer "In4.Cu")
		(net "IRQ_LVC3_WAKE_N")
	)
	(segment
		(start 304.17008 -14.468348)
		(end 304.17008 -13.731748)
		(width 0.127)
		(layer "In4.Cu")
		(net "IRQ_LVC3_WAKE_N")
	)
	(segment
		(start 191.11468 -12.055348)
		(end 191.62268 -12.563348)
		(width 0.127)
		(layer "In4.Cu")
		(net "IRQ_LVC3_WAKE_N")
	)
	(segment
		(start 261.18058 -33.175448)
		(end 264.80008 -29.555948)
		(width 0.127)
		(layer "In4.Cu")
		(net "IRQ_LVC3_WAKE_N")
	)
	(segment
		(start 220.45168 -13.020548)
		(end 222.01378 -14.582648)
		(width 0.127)
		(layer "In4.Cu")
		(net "IRQ_LVC3_WAKE_N")
	)
	(segment
		(start 258.49072 -36.972748)
		(end 261.18058 -34.282888)
		(width 0.127)
		(layer "In4.Cu")
		(net "IRQ_LVC3_WAKE_N")
	)
	(segment
		(start 222.01378 -14.582648)
		(end 222.01378 -34.482278)
		(width 0.127)
		(layer "In4.Cu")
		(net "IRQ_LVC3_WAKE_N")
	)
	(segment
		(start 224.953322 -36.972748)
		(end 258.49072 -36.972748)
		(width 0.127)
		(layer "In4.Cu")
		(net "IRQ_LVC3_WAKE_N")
	)
	(segment
		(start 188.72708 -7.051548)
		(end 191.11468 -9.439148)
		(width 0.127)
		(layer "In4.Cu")
		(net "IRQ_LVC3_WAKE_N")
	)
	(segment
		(start 282.228036 -14.138148)
		(end 282.188158 -14.09827)
		(width 0.127)
		(layer "In4.Cu")
		(net "IRQ_LVC3_WAKE_N")
	)
	(segment
		(start 191.11468 -9.439148)
		(end 191.11468 -12.055348)
		(width 0.127)
		(layer "In4.Cu")
		(net "IRQ_LVC3_WAKE_N")
	)
	(segment
		(start 161.85388 -7.991348)
		(end 162.79368 -7.051548)
		(width 0.127)
		(layer "In4.Cu")
		(net "IRQ_LVC3_WAKE_N")
	)
	(segment
		(start 261.18058 -34.282888)
		(end 261.18058 -33.175448)
		(width 0.127)
		(layer "In4.Cu")
		(net "IRQ_LVC3_WAKE_N")
	)
	(segment
		(start 264.80008 -29.555948)
		(end 268.02588 -29.555948)
		(width 0.127)
		(layer "In4.Cu")
		(net "IRQ_LVC3_WAKE_N")
	)
	(segment
		(start 222.01378 -34.482278)
		(end 222.287592 -35.14344)
		(width 0.127)
		(layer "In4.Cu")
		(net "IRQ_LVC3_WAKE_N")
	)
	(segment
		(start 162.79368 -7.051548)
		(end 188.72708 -7.051548)
		(width 0.127)
		(layer "In4.Cu")
		(net "IRQ_LVC3_WAKE_N")
	)
	(segment
		(start 191.62268 -12.563348)
		(end 193.42608 -12.563348)
		(width 0.127)
		(layer "In4.Cu")
		(net "IRQ_LVC3_WAKE_N")
	)
	(segment
		(start 272.80108 -24.780748)
		(end 272.80108 -16.855948)
		(width 0.127)
		(layer "In4.Cu")
		(net "IRQ_LVC3_WAKE_N")
	)
	(segment
		(start 304.17008 -13.731748)
		(end 303.61128 -13.172948)
		(width 0.127)
		(layer "In4.Cu")
		(net "IRQ_LVC3_WAKE_N")
	)
	(segment
		(start 222.287592 -35.14344)
		(end 223.525334 -36.381182)
		(width 0.127)
		(layer "In4.Cu")
		(net "IRQ_LVC3_WAKE_N")
	)
	(segment
		(start 223.525334 -36.381182)
		(end 224.953322 -36.972748)
		(width 0.127)
		(layer "In4.Cu")
		(net "IRQ_LVC3_WAKE_N")
	)
	(segment
		(start 193.42608 -12.563348)
		(end 193.88328 -13.020548)
		(width 0.127)
		(layer "In4.Cu")
		(net "IRQ_LVC3_WAKE_N")
	)
	(segment
		(start 289.26028 -13.172948)
		(end 288.29508 -14.138148)
		(width 0.127)
		(layer "In4.Cu")
		(net "IRQ_LVC3_WAKE_N")
	)
	(segment
		(start 303.61128 -13.172948)
		(end 289.26028 -13.172948)
		(width 0.127)
		(layer "In4.Cu")
		(net "IRQ_LVC3_WAKE_N")
	)
	(segment
		(start 272.80108 -16.855948)
		(end 275.558758 -14.09827)
		(width 0.127)
		(layer "In4.Cu")
		(net "IRQ_LVC3_WAKE_N")
	)
	(segment
		(start 193.88328 -13.020548)
		(end 220.45168 -13.020548)
		(width 0.127)
		(layer "In4.Cu")
		(net "IRQ_LVC3_WAKE_N")
	)
	(segment
		(start 288.29508 -14.138148)
		(end 282.228036 -14.138148)
		(width 0.127)
		(layer "In4.Cu")
		(net "IRQ_LVC3_WAKE_N")
	)
	(segment
		(start 310.770778 -15.64132)
		(end 308.62778 -15.64132)
		(width 0.12954)
		(layer "F.Cu")
		(net "IRQ_LVC3_WAKE_BUF_N")
	)
	(segment
		(start 308.62778 -15.64132)
		(end 306.795424 -15.64132)
		(width 0.12954)
		(layer "F.Cu")
		(net "IRQ_LVC3_WAKE_BUF_N")
	)
	(segment
		(start 306.795424 -15.64132)
		(end 306.663344 -15.50924)
		(width 0.12954)
		(layer "F.Cu")
		(net "IRQ_LVC3_WAKE_BUF_N")
	)
	(segment
		(start 306.663344 -14.51102)
		(end 306.663344 -15.50924)
		(width 0.12954)
		(layer "F.Cu")
		(net "IRQ_LVC3_WAKE_BUF_N")
	)
	(via
		(at 308.62778 -15.64132)
		(size 0.762)
		(drill 0.381)
		(layers "F.Cu" "B.Cu")
		(net "IRQ_LVC3_WAKE_BUF_N")
	)
	(segment
		(start 451.36181 -8.320024)
		(end 451.36181 -7.4041)
		(width 0.12954)
		(layer "F.Cu")
		(net "IRQ_LVC3_OCP_SFF_WAKE_N")
	)
	(segment
		(start 451.36181 -7.4041)
		(end 451.370446 -7.395464)
		(width 0.12954)
		(layer "F.Cu")
		(net "IRQ_LVC3_OCP_SFF_WAKE_N")
	)
	(segment
		(start 460.58455 -45.693838)
		(end 460.60868 -45.669708)
		(width 0.12954)
		(layer "F.Cu")
		(net "IRQ_LVC3_OCP_SFF_WAKE_N")
	)
	(segment
		(start 460.58455 -45.023278)
		(end 460.58455 -45.693838)
		(width 0.12954)
		(layer "F.Cu")
		(net "IRQ_LVC3_OCP_SFF_WAKE_N")
	)
	(segment
		(start 460.60868 -45.669708)
		(end 463.06359 -45.669708)
		(width 0.12954)
		(layer "F.Cu")
		(net "IRQ_LVC3_OCP_SFF_WAKE_N")
	)
	(segment
		(start 451.370446 -7.395464)
		(end 451.370446 -7.046214)
		(width 0.12954)
		(layer "F.Cu")
		(net "IRQ_LVC3_OCP_SFF_WAKE_N")
	)
	(segment
		(start 451.370446 -7.046214)
		(end 451.06082 -6.736588)
		(width 0.12954)
		(layer "F.Cu")
		(net "IRQ_LVC3_OCP_SFF_WAKE_N")
	)
	(via
		(at 460.58455 -45.023278)
		(size 0.508)
		(drill 0.254)
		(layers "F.Cu" "B.Cu")
		(net "IRQ_LVC3_OCP_SFF_WAKE_N")
	)
	(via
		(at 451.06082 -6.736588)
		(size 0.508)
		(drill 0.254)
		(layers "F.Cu" "B.Cu")
		(net "IRQ_LVC3_OCP_SFF_WAKE_N")
	)
	(segment
		(start 452.45528 -9.698228)
		(end 451.06082 -8.303768)
		(width 0.127)
		(layer "In2.Cu")
		(net "IRQ_LVC3_OCP_SFF_WAKE_N")
	)
	(segment
		(start 451.06082 -8.303768)
		(end 451.06082 -6.736588)
		(width 0.127)
		(layer "In2.Cu")
		(net "IRQ_LVC3_OCP_SFF_WAKE_N")
	)
	(segment
		(start 457.49972 -38.821868)
		(end 457.92136 -38.400228)
		(width 0.127)
		(layer "In2.Cu")
		(net "IRQ_LVC3_OCP_SFF_WAKE_N")
	)
	(segment
		(start 457.92136 -38.400228)
		(end 457.92136 -16.810228)
		(width 0.127)
		(layer "In2.Cu")
		(net "IRQ_LVC3_OCP_SFF_WAKE_N")
	)
	(segment
		(start 457.92136 -16.810228)
		(end 452.45528 -11.344148)
		(width 0.127)
		(layer "In2.Cu")
		(net "IRQ_LVC3_OCP_SFF_WAKE_N")
	)
	(segment
		(start 460.58455 -45.023278)
		(end 457.49972 -41.938448)
		(width 0.127)
		(layer "In2.Cu")
		(net "IRQ_LVC3_OCP_SFF_WAKE_N")
	)
	(segment
		(start 457.49972 -41.938448)
		(end 457.49972 -38.821868)
		(width 0.127)
		(layer "In2.Cu")
		(net "IRQ_LVC3_OCP_SFF_WAKE_N")
	)
	(segment
		(start 452.45528 -11.344148)
		(end 452.45528 -9.698228)
		(width 0.127)
		(layer "In2.Cu")
		(net "IRQ_LVC3_OCP_SFF_WAKE_N")
	)
	(segment
		(start 333.89824 -38.182804)
		(end 333.621888 -37.769292)
		(width 0.0889)
		(layer "F.Cu")
		(net "IRQ_LPC_SERIRQ_ESPI_CS1_N")
	)
	(segment
		(start 331.517752 -20.77085)
		(end 331.517752 -22.10689)
		(width 0.12954)
		(layer "F.Cu")
		(net "IRQ_LPC_SERIRQ_ESPI_CS1_N")
	)
	(segment
		(start 333.65821 -34.957004)
		(end 332.337918 -33.636712)
		(width 0.0889)
		(layer "F.Cu")
		(net "IRQ_LPC_SERIRQ_ESPI_CS1_N")
	)
	(segment
		(start 332.337918 -33.636712)
		(end 332.337918 -30.93974)
		(width 0.0889)
		(layer "F.Cu")
		(net "IRQ_LPC_SERIRQ_ESPI_CS1_N")
	)
	(segment
		(start 332.527656 -30.750002)
		(end 332.527656 -30.589728)
		(width 0.0889)
		(layer "F.Cu")
		(net "IRQ_LPC_SERIRQ_ESPI_CS1_N")
	)
	(segment
		(start 331.7748 -25.317704)
		(end 331.577188 -25.515316)
		(width 0.12954)
		(layer "F.Cu")
		(net "IRQ_LPC_SERIRQ_ESPI_CS1_N")
	)
	(segment
		(start 331.425804 -25.6667)
		(end 331.577188 -25.515316)
		(width 0.12954)
		(layer "F.Cu")
		(net "IRQ_LPC_SERIRQ_ESPI_CS1_N")
	)
	(segment
		(start 331.517752 -22.10689)
		(end 331.7748 -22.363938)
		(width 0.12954)
		(layer "F.Cu")
		(net "IRQ_LPC_SERIRQ_ESPI_CS1_N")
	)
	(segment
		(start 331.425804 -27.690064)
		(end 331.425804 -25.6667)
		(width 0.12954)
		(layer "F.Cu")
		(net "IRQ_LPC_SERIRQ_ESPI_CS1_N")
	)
	(segment
		(start 333.621888 -37.769292)
		(end 333.621888 -37.492432)
		(width 0.0889)
		(layer "F.Cu")
		(net "IRQ_LPC_SERIRQ_ESPI_CS1_N")
	)
	(segment
		(start 333.89824 -38.465252)
		(end 333.89824 -38.182804)
		(width 0.0889)
		(layer "F.Cu")
		(net "IRQ_LPC_SERIRQ_ESPI_CS1_N")
	)
	(segment
		(start 333.621888 -37.492432)
		(end 333.65821 -37.368988)
		(width 0.0889)
		(layer "F.Cu")
		(net "IRQ_LPC_SERIRQ_ESPI_CS1_N")
	)
	(segment
		(start 331.932534 -29.209746)
		(end 331.425804 -27.690064)
		(width 0.12954)
		(layer "F.Cu")
		(net "IRQ_LPC_SERIRQ_ESPI_CS1_N")
	)
	(segment
		(start 333.65821 -37.368988)
		(end 333.65821 -34.957004)
		(width 0.0889)
		(layer "F.Cu")
		(net "IRQ_LPC_SERIRQ_ESPI_CS1_N")
	)
	(segment
		(start 331.029056 -19.77771)
		(end 331.029056 -19.99615)
		(width 0.12954)
		(layer "F.Cu")
		(net "IRQ_LPC_SERIRQ_ESPI_CS1_N")
	)
	(segment
		(start 332.337918 -30.93974)
		(end 332.527656 -30.750002)
		(width 0.0889)
		(layer "F.Cu")
		(net "IRQ_LPC_SERIRQ_ESPI_CS1_N")
	)
	(segment
		(start 331.7748 -22.363938)
		(end 331.7748 -25.317704)
		(width 0.12954)
		(layer "F.Cu")
		(net "IRQ_LPC_SERIRQ_ESPI_CS1_N")
	)
	(segment
		(start 331.029056 -19.99615)
		(end 331.517752 -20.484846)
		(width 0.12954)
		(layer "F.Cu")
		(net "IRQ_LPC_SERIRQ_ESPI_CS1_N")
	)
	(segment
		(start 332.527656 -29.804868)
		(end 331.932534 -29.209746)
		(width 0.12954)
		(layer "F.Cu")
		(net "IRQ_LPC_SERIRQ_ESPI_CS1_N")
	)
	(segment
		(start 332.527656 -30.589728)
		(end 332.527656 -29.804868)
		(width 0.12954)
		(layer "F.Cu")
		(net "IRQ_LPC_SERIRQ_ESPI_CS1_N")
	)
	(segment
		(start 331.517752 -20.484846)
		(end 331.517752 -20.77085)
		(width 0.12954)
		(layer "F.Cu")
		(net "IRQ_LPC_SERIRQ_ESPI_CS1_N")
	)
	(via
		(at 331.577188 -25.515316)
		(size 0.762)
		(drill 0.381)
		(layers "F.Cu" "B.Cu")
		(net "IRQ_LPC_SERIRQ_ESPI_CS1_N")
	)
	(segment
		(start 337.792314 -22.202648)
		(end 337.104228 -22.202648)
		(width 0.12954)
		(layer "F.Cu")
		(net "IRQ_LPC_PIRQA_N_ESPI_ALERT0_R_N")
	)
	(segment
		(start 336.870294 -22.436582)
		(end 336.32648 -22.436582)
		(width 0.12954)
		(layer "F.Cu")
		(net "IRQ_LPC_PIRQA_N_ESPI_ALERT0_R_N")
	)
	(segment
		(start 337.792314 -20.434554)
		(end 337.792314 -22.202648)
		(width 0.12954)
		(layer "F.Cu")
		(net "IRQ_LPC_PIRQA_N_ESPI_ALERT0_R_N")
	)
	(segment
		(start 337.104228 -22.202648)
		(end 336.870294 -22.436582)
		(width 0.12954)
		(layer "F.Cu")
		(net "IRQ_LPC_PIRQA_N_ESPI_ALERT0_R_N")
	)
	(via
		(at 337.792314 -22.202648)
		(size 0.762)
		(drill 0.381)
		(layers "F.Cu" "B.Cu")
		(net "IRQ_LPC_PIRQA_N_ESPI_ALERT0_R_N")
	)
	(segment
		(start 336.98053 -25.444704)
		(end 336.98053 -24.623776)
		(width 0.12954)
		(layer "F.Cu")
		(net "IRQ_LPC_PIRQA_N_ESPI_ALERT0_N")
	)
	(segment
		(start 335.899252 -37.364924)
		(end 335.837022 -37.302694)
		(width 0.0889)
		(layer "F.Cu")
		(net "IRQ_LPC_PIRQA_N_ESPI_ALERT0_N")
	)
	(segment
		(start 336.98053 -24.623776)
		(end 337.792314 -23.811992)
		(width 0.12954)
		(layer "F.Cu")
		(net "IRQ_LPC_PIRQA_N_ESPI_ALERT0_N")
	)
	(segment
		(start 335.68513 -30.396434)
		(end 335.65846 -30.331918)
		(width 0.0889)
		(layer "F.Cu")
		(net "IRQ_LPC_PIRQA_N_ESPI_ALERT0_N")
	)
	(segment
		(start 335.899252 -37.63518)
		(end 335.899252 -37.364924)
		(width 0.0889)
		(layer "F.Cu")
		(net "IRQ_LPC_PIRQA_N_ESPI_ALERT0_N")
	)
	(segment
		(start 335.837022 -37.302694)
		(end 335.837022 -34.238184)
		(width 0.0889)
		(layer "F.Cu")
		(net "IRQ_LPC_PIRQA_N_ESPI_ALERT0_N")
	)
	(segment
		(start 335.837022 -34.238184)
		(end 336.266282 -33.808924)
		(width 0.0889)
		(layer "F.Cu")
		(net "IRQ_LPC_PIRQA_N_ESPI_ALERT0_N")
	)
	(segment
		(start 336.60588 -25.819354)
		(end 336.98053 -25.444704)
		(width 0.12954)
		(layer "F.Cu")
		(net "IRQ_LPC_PIRQA_N_ESPI_ALERT0_N")
	)
	(segment
		(start 337.217004 -23.236682)
		(end 337.792314 -23.811992)
		(width 0.12954)
		(layer "F.Cu")
		(net "IRQ_LPC_PIRQA_N_ESPI_ALERT0_N")
	)
	(segment
		(start 336.32648 -23.236682)
		(end 337.217004 -23.236682)
		(width 0.12954)
		(layer "F.Cu")
		(net "IRQ_LPC_PIRQA_N_ESPI_ALERT0_N")
	)
	(segment
		(start 336.266282 -33.808924)
		(end 336.266282 -31.33217)
		(width 0.0889)
		(layer "F.Cu")
		(net "IRQ_LPC_PIRQA_N_ESPI_ALERT0_N")
	)
	(segment
		(start 336.015584 -30.726126)
		(end 335.68513 -30.396434)
		(width 0.0889)
		(layer "F.Cu")
		(net "IRQ_LPC_PIRQA_N_ESPI_ALERT0_N")
	)
	(segment
		(start 336.180684 -28.749752)
		(end 336.60588 -28.324556)
		(width 0.12954)
		(layer "F.Cu")
		(net "IRQ_LPC_PIRQA_N_ESPI_ALERT0_N")
	)
	(segment
		(start 335.65846 -30.331918)
		(end 335.65846 -29.271976)
		(width 0.12954)
		(layer "F.Cu")
		(net "IRQ_LPC_PIRQA_N_ESPI_ALERT0_N")
	)
	(segment
		(start 335.65846 -29.271976)
		(end 336.180684 -28.749752)
		(width 0.12954)
		(layer "F.Cu")
		(net "IRQ_LPC_PIRQA_N_ESPI_ALERT0_N")
	)
	(segment
		(start 336.60588 -28.324556)
		(end 336.60588 -25.819354)
		(width 0.12954)
		(layer "F.Cu")
		(net "IRQ_LPC_PIRQA_N_ESPI_ALERT0_N")
	)
	(segment
		(start 336.266282 -31.33217)
		(end 336.015584 -30.726126)
		(width 0.0889)
		(layer "F.Cu")
		(net "IRQ_LPC_PIRQA_N_ESPI_ALERT0_N")
	)
	(via
		(at 336.180684 -28.749752)
		(size 0.762)
		(drill 0.381)
		(layers "F.Cu" "B.Cu")
		(net "IRQ_LPC_PIRQA_N_ESPI_ALERT0_N")
	)
	(segment
		(start 177.666904 -16.550132)
		(end 177.66665 -16.550386)
		(width 0.12954)
		(layer "F.Cu")
		(net "IRQ_ESPI_LPC_SERIRQ_ALERT_R_N")
	)
	(segment
		(start 177.66665 -16.550386)
		(end 177.66665 -17.775428)
		(width 0.12954)
		(layer "F.Cu")
		(net "IRQ_ESPI_LPC_SERIRQ_ALERT_R_N")
	)
	(segment
		(start 335.604866 -14.926818)
		(end 335.604866 -15.650718)
		(width 0.12954)
		(layer "F.Cu")
		(net "IRQ_ESPI_LPC_SERIRQ_ALERT_R_N")
	)
	(segment
		(start 335.604866 -15.650718)
		(end 335.754726 -15.800578)
		(width 0.12954)
		(layer "F.Cu")
		(net "IRQ_ESPI_LPC_SERIRQ_ALERT_R_N")
	)
	(via
		(at 272.26768 -13.680948)
		(size 0.508)
		(drill 0.254)
		(layers "F.Cu" "B.Cu")
		(net "IRQ_ESPI_LPC_SERIRQ_ALERT_R_N")
	)
	(via
		(at 335.604866 -14.926818)
		(size 0.508)
		(drill 0.254)
		(layers "F.Cu" "B.Cu")
		(net "IRQ_ESPI_LPC_SERIRQ_ALERT_R_N")
	)
	(via
		(at 260.76148 -31.918148)
		(size 0.508)
		(drill 0.254)
		(layers "F.Cu" "B.Cu")
		(net "IRQ_ESPI_LPC_SERIRQ_ALERT_R_N")
	)
	(via
		(at 177.66665 -17.775428)
		(size 0.508)
		(drill 0.254)
		(layers "F.Cu" "B.Cu")
		(net "IRQ_ESPI_LPC_SERIRQ_ALERT_R_N")
	)
	(segment
		(start 335.604866 -14.926818)
		(end 335.604866 -13.873734)
		(width 0.127)
		(layer "In2.Cu")
		(net "IRQ_ESPI_LPC_SERIRQ_ALERT_R_N")
	)
	(segment
		(start 288.24428 -14.315948)
		(end 285.93288 -14.315948)
		(width 0.127)
		(layer "In2.Cu")
		(net "IRQ_ESPI_LPC_SERIRQ_ALERT_R_N")
	)
	(segment
		(start 221.03588 -34.148268)
		(end 223.59366 -36.706048)
		(width 0.127)
		(layer "In2.Cu")
		(net "IRQ_ESPI_LPC_SERIRQ_ALERT_R_N")
	)
	(segment
		(start 297.03268 -13.884148)
		(end 288.67608 -13.884148)
		(width 0.127)
		(layer "In2.Cu")
		(net "IRQ_ESPI_LPC_SERIRQ_ALERT_R_N")
	)
	(segment
		(start 258.6609 -36.706048)
		(end 260.76148 -34.605468)
		(width 0.127)
		(layer "In2.Cu")
		(net "IRQ_ESPI_LPC_SERIRQ_ALERT_R_N")
	)
	(segment
		(start 285.93288 -14.315948)
		(end 284.78988 -13.172948)
		(width 0.127)
		(layer "In2.Cu")
		(net "IRQ_ESPI_LPC_SERIRQ_ALERT_R_N")
	)
	(segment
		(start 177.66665 -17.746218)
		(end 181.42712 -13.985748)
		(width 0.127)
		(layer "In2.Cu")
		(net "IRQ_ESPI_LPC_SERIRQ_ALERT_R_N")
	)
	(segment
		(start 335.00568 -13.274548)
		(end 321.79768 -13.274548)
		(width 0.127)
		(layer "In2.Cu")
		(net "IRQ_ESPI_LPC_SERIRQ_ALERT_R_N")
	)
	(segment
		(start 177.66665 -17.775428)
		(end 177.66665 -17.746218)
		(width 0.127)
		(layer "In2.Cu")
		(net "IRQ_ESPI_LPC_SERIRQ_ALERT_R_N")
	)
	(segment
		(start 288.67608 -13.884148)
		(end 288.24428 -14.315948)
		(width 0.127)
		(layer "In2.Cu")
		(net "IRQ_ESPI_LPC_SERIRQ_ALERT_R_N")
	)
	(segment
		(start 221.03588 -16.398748)
		(end 221.03588 -34.148268)
		(width 0.127)
		(layer "In2.Cu")
		(net "IRQ_ESPI_LPC_SERIRQ_ALERT_R_N")
	)
	(segment
		(start 321.26936 -13.802868)
		(end 311.3024 -13.802868)
		(width 0.127)
		(layer "In2.Cu")
		(net "IRQ_ESPI_LPC_SERIRQ_ALERT_R_N")
	)
	(segment
		(start 223.59366 -36.706048)
		(end 258.6609 -36.706048)
		(width 0.127)
		(layer "In2.Cu")
		(net "IRQ_ESPI_LPC_SERIRQ_ALERT_R_N")
	)
	(segment
		(start 321.79768 -13.274548)
		(end 321.26936 -13.802868)
		(width 0.127)
		(layer "In2.Cu")
		(net "IRQ_ESPI_LPC_SERIRQ_ALERT_R_N")
	)
	(segment
		(start 335.604866 -13.873734)
		(end 335.00568 -13.274548)
		(width 0.127)
		(layer "In2.Cu")
		(net "IRQ_ESPI_LPC_SERIRQ_ALERT_R_N")
	)
	(segment
		(start 311.3024 -13.802868)
		(end 310.53659 -13.037058)
		(width 0.127)
		(layer "In2.Cu")
		(net "IRQ_ESPI_LPC_SERIRQ_ALERT_R_N")
	)
	(segment
		(start 193.93408 -14.544548)
		(end 219.18168 -14.544548)
		(width 0.127)
		(layer "In2.Cu")
		(net "IRQ_ESPI_LPC_SERIRQ_ALERT_R_N")
	)
	(segment
		(start 193.37528 -13.985748)
		(end 193.93408 -14.544548)
		(width 0.127)
		(layer "In2.Cu")
		(net "IRQ_ESPI_LPC_SERIRQ_ALERT_R_N")
	)
	(segment
		(start 284.78988 -13.172948)
		(end 272.77568 -13.172948)
		(width 0.127)
		(layer "In2.Cu")
		(net "IRQ_ESPI_LPC_SERIRQ_ALERT_R_N")
	)
	(segment
		(start 297.87977 -13.037058)
		(end 297.03268 -13.884148)
		(width 0.127)
		(layer "In2.Cu")
		(net "IRQ_ESPI_LPC_SERIRQ_ALERT_R_N")
	)
	(segment
		(start 260.76148 -34.605468)
		(end 260.76148 -31.918148)
		(width 0.127)
		(layer "In2.Cu")
		(net "IRQ_ESPI_LPC_SERIRQ_ALERT_R_N")
	)
	(segment
		(start 219.18168 -14.544548)
		(end 221.03588 -16.398748)
		(width 0.127)
		(layer "In2.Cu")
		(net "IRQ_ESPI_LPC_SERIRQ_ALERT_R_N")
	)
	(segment
		(start 310.53659 -13.037058)
		(end 297.87977 -13.037058)
		(width 0.127)
		(layer "In2.Cu")
		(net "IRQ_ESPI_LPC_SERIRQ_ALERT_R_N")
	)
	(segment
		(start 272.77568 -13.172948)
		(end 272.26768 -13.680948)
		(width 0.127)
		(layer "In2.Cu")
		(net "IRQ_ESPI_LPC_SERIRQ_ALERT_R_N")
	)
	(segment
		(start 181.42712 -13.985748)
		(end 193.37528 -13.985748)
		(width 0.127)
		(layer "In2.Cu")
		(net "IRQ_ESPI_LPC_SERIRQ_ALERT_R_N")
	)
	(segment
		(start 264.49528 -28.895548)
		(end 261.47268 -31.918148)
		(width 0.127)
		(layer "In4.Cu")
		(net "IRQ_ESPI_LPC_SERIRQ_ALERT_R_N")
	)
	(segment
		(start 272.26768 -13.680948)
		(end 272.26768 -24.475948)
		(width 0.127)
		(layer "In4.Cu")
		(net "IRQ_ESPI_LPC_SERIRQ_ALERT_R_N")
	)
	(segment
		(start 272.26768 -24.475948)
		(end 267.84808 -28.895548)
		(width 0.127)
		(layer "In4.Cu")
		(net "IRQ_ESPI_LPC_SERIRQ_ALERT_R_N")
	)
	(segment
		(start 267.84808 -28.895548)
		(end 264.49528 -28.895548)
		(width 0.127)
		(layer "In4.Cu")
		(net "IRQ_ESPI_LPC_SERIRQ_ALERT_R_N")
	)
	(segment
		(start 261.47268 -31.918148)
		(end 260.76148 -31.918148)
		(width 0.127)
		(layer "In4.Cu")
		(net "IRQ_ESPI_LPC_SERIRQ_ALERT_R_N")
	)
	(segment
		(start 335.754726 -16.600678)
		(end 335.850992 -16.696944)
		(width 0.12954)
		(layer "F.Cu")
		(net "IRQ_ESPI_LPC_SERIRQ_ALERT_N")
	)
	(segment
		(start 335.850992 -17.395698)
		(end 336.492342 -18.037048)
		(width 0.12954)
		(layer "F.Cu")
		(net "IRQ_ESPI_LPC_SERIRQ_ALERT_N")
	)
	(segment
		(start 336.492342 -18.037048)
		(end 336.492342 -18.434558)
		(width 0.12954)
		(layer "F.Cu")
		(net "IRQ_ESPI_LPC_SERIRQ_ALERT_N")
	)
	(segment
		(start 335.850992 -16.696944)
		(end 335.850992 -17.395698)
		(width 0.12954)
		(layer "F.Cu")
		(net "IRQ_ESPI_LPC_SERIRQ_ALERT_N")
	)
	(via
		(at 335.850992 -17.395698)
		(size 0.508)
		(drill 0.254)
		(layers "F.Cu" "B.Cu")
		(net "IRQ_ESPI_LPC_SERIRQ_ALERT_N")
	)
	(segment
		(start 189.469776 -107.375452)
		(end 186.955684 -107.375452)
		(width 0.12954)
		(layer "F.Cu")
		(net "IRQ_BMC_PCH_NMI_R")
	)
	(segment
		(start 328.885296 -20.616926)
		(end 329.20686 -20.616926)
		(width 0.12954)
		(layer "F.Cu")
		(net "IRQ_BMC_PCH_NMI_R")
	)
	(segment
		(start 200.08088 -103.723948)
		(end 199.39762 -103.040688)
		(width 0.12954)
		(layer "F.Cu")
		(net "IRQ_BMC_PCH_NMI_R")
	)
	(segment
		(start 328.537316 -20.632928)
		(end 328.869294 -20.632928)
		(width 0.12954)
		(layer "F.Cu")
		(net "IRQ_BMC_PCH_NMI_R")
	)
	(segment
		(start 191.76873 -103.245158)
		(end 191.76873 -106.476038)
		(width 0.12954)
		(layer "F.Cu")
		(net "IRQ_BMC_PCH_NMI_R")
	)
	(segment
		(start 191.76873 -106.476038)
		(end 190.77178 -107.472988)
		(width 0.12954)
		(layer "F.Cu")
		(net "IRQ_BMC_PCH_NMI_R")
	)
	(segment
		(start 328.869294 -20.632928)
		(end 328.885296 -20.616926)
		(width 0.12954)
		(layer "F.Cu")
		(net "IRQ_BMC_PCH_NMI_R")
	)
	(segment
		(start 190.77178 -107.472988)
		(end 189.567312 -107.472988)
		(width 0.12954)
		(layer "F.Cu")
		(net "IRQ_BMC_PCH_NMI_R")
	)
	(segment
		(start 189.567312 -107.472988)
		(end 189.469776 -107.375452)
		(width 0.12954)
		(layer "F.Cu")
		(net "IRQ_BMC_PCH_NMI_R")
	)
	(segment
		(start 199.39762 -103.040688)
		(end 191.9732 -103.040688)
		(width 0.12954)
		(layer "F.Cu")
		(net "IRQ_BMC_PCH_NMI_R")
	)
	(segment
		(start 191.9732 -103.040688)
		(end 191.76873 -103.245158)
		(width 0.12954)
		(layer "F.Cu")
		(net "IRQ_BMC_PCH_NMI_R")
	)
	(via
		(at 200.08088 -103.723948)
		(size 0.508)
		(drill 0.254)
		(layers "F.Cu" "B.Cu")
		(net "IRQ_BMC_PCH_NMI_R")
	)
	(via
		(at 328.537316 -20.632928)
		(size 0.508)
		(drill 0.254)
		(layers "F.Cu" "B.Cu")
		(net "IRQ_BMC_PCH_NMI_R")
	)
	(via
		(at 199.39 -90.17)
		(size 0.508)
		(drill 0.254)
		(layers "F.Cu" "B.Cu")
		(net "IRQ_BMC_PCH_NMI_R")
	)
	(segment
		(start 199.39 -103.033068)
		(end 200.08088 -103.723948)
		(width 0.127)
		(layer "In2.Cu")
		(net "IRQ_BMC_PCH_NMI_R")
	)
	(segment
		(start 199.39 -90.17)
		(end 199.39 -103.033068)
		(width 0.127)
		(layer "In2.Cu")
		(net "IRQ_BMC_PCH_NMI_R")
	)
	(segment
		(start 222.28048 -81.270348)
		(end 233.78668 -69.764148)
		(width 0.127)
		(layer "In15.Cu")
		(net "IRQ_BMC_PCH_NMI_R")
	)
	(segment
		(start 319.25768 -22.520148)
		(end 320.12128 -21.656548)
		(width 0.127)
		(layer "In15.Cu")
		(net "IRQ_BMC_PCH_NMI_R")
	)
	(segment
		(start 297.16222 -35.552888)
		(end 297.16222 -33.912048)
		(width 0.127)
		(layer "In15.Cu")
		(net "IRQ_BMC_PCH_NMI_R")
	)
	(segment
		(start 276.15388 -61.839348)
		(end 290.53028 -47.462948)
		(width 0.127)
		(layer "In15.Cu")
		(net "IRQ_BMC_PCH_NMI_R")
	)
	(segment
		(start 199.39 -90.17)
		(end 199.39 -82.850228)
		(width 0.127)
		(layer "In15.Cu")
		(net "IRQ_BMC_PCH_NMI_R")
	)
	(segment
		(start 319.25768 -24.729948)
		(end 319.25768 -22.520148)
		(width 0.127)
		(layer "In15.Cu")
		(net "IRQ_BMC_PCH_NMI_R")
	)
	(segment
		(start 233.78668 -69.764148)
		(end 243.45392 -69.764148)
		(width 0.127)
		(layer "In15.Cu")
		(net "IRQ_BMC_PCH_NMI_R")
	)
	(segment
		(start 327.513696 -21.656548)
		(end 328.537316 -20.632928)
		(width 0.127)
		(layer "In15.Cu")
		(net "IRQ_BMC_PCH_NMI_R")
	)
	(segment
		(start 290.53028 -43.876468)
		(end 293.9923 -40.414448)
		(width 0.127)
		(layer "In15.Cu")
		(net "IRQ_BMC_PCH_NMI_R")
	)
	(segment
		(start 251.36983 -66.836798)
		(end 252.785626 -65.421002)
		(width 0.127)
		(layer "In15.Cu")
		(net "IRQ_BMC_PCH_NMI_R")
	)
	(segment
		(start 262.10768 -63.566548)
		(end 271.68348 -63.566548)
		(width 0.127)
		(layer "In15.Cu")
		(net "IRQ_BMC_PCH_NMI_R")
	)
	(segment
		(start 200.96988 -81.270348)
		(end 222.28048 -81.270348)
		(width 0.127)
		(layer "In15.Cu")
		(net "IRQ_BMC_PCH_NMI_R")
	)
	(segment
		(start 293.9923 -38.722808)
		(end 297.16222 -35.552888)
		(width 0.127)
		(layer "In15.Cu")
		(net "IRQ_BMC_PCH_NMI_R")
	)
	(segment
		(start 252.785626 -65.421002)
		(end 262.10768 -63.566548)
		(width 0.127)
		(layer "In15.Cu")
		(net "IRQ_BMC_PCH_NMI_R")
	)
	(segment
		(start 293.9923 -40.414448)
		(end 293.9923 -38.722808)
		(width 0.127)
		(layer "In15.Cu")
		(net "IRQ_BMC_PCH_NMI_R")
	)
	(segment
		(start 318.14008 -25.847548)
		(end 319.25768 -24.729948)
		(width 0.127)
		(layer "In15.Cu")
		(net "IRQ_BMC_PCH_NMI_R")
	)
	(segment
		(start 199.39 -82.850228)
		(end 200.96988 -81.270348)
		(width 0.127)
		(layer "In15.Cu")
		(net "IRQ_BMC_PCH_NMI_R")
	)
	(segment
		(start 271.68348 -63.566548)
		(end 273.41068 -61.839348)
		(width 0.127)
		(layer "In15.Cu")
		(net "IRQ_BMC_PCH_NMI_R")
	)
	(segment
		(start 273.41068 -61.839348)
		(end 276.15388 -61.839348)
		(width 0.127)
		(layer "In15.Cu")
		(net "IRQ_BMC_PCH_NMI_R")
	)
	(segment
		(start 246.38127 -66.836798)
		(end 251.36983 -66.836798)
		(width 0.127)
		(layer "In15.Cu")
		(net "IRQ_BMC_PCH_NMI_R")
	)
	(segment
		(start 290.53028 -47.462948)
		(end 290.53028 -43.876468)
		(width 0.127)
		(layer "In15.Cu")
		(net "IRQ_BMC_PCH_NMI_R")
	)
	(segment
		(start 305.22672 -25.847548)
		(end 318.14008 -25.847548)
		(width 0.127)
		(layer "In15.Cu")
		(net "IRQ_BMC_PCH_NMI_R")
	)
	(segment
		(start 320.12128 -21.656548)
		(end 327.513696 -21.656548)
		(width 0.127)
		(layer "In15.Cu")
		(net "IRQ_BMC_PCH_NMI_R")
	)
	(segment
		(start 297.16222 -33.912048)
		(end 305.22672 -25.847548)
		(width 0.127)
		(layer "In15.Cu")
		(net "IRQ_BMC_PCH_NMI_R")
	)
	(segment
		(start 243.45392 -69.764148)
		(end 246.38127 -66.836798)
		(width 0.127)
		(layer "In15.Cu")
		(net "IRQ_BMC_PCH_NMI_R")
	)
	(segment
		(start 330.348844 -22.243796)
		(end 330.444856 -22.339808)
		(width 0.12954)
		(layer "F.Cu")
		(net "IRQ_BMC_PCH_NMI")
	)
	(segment
		(start 330.3778 -28.191714)
		(end 330.3778 -24.934164)
		(width 0.12954)
		(layer "F.Cu")
		(net "IRQ_BMC_PCH_NMI")
	)
	(segment
		(start 332.397608 -35.044634)
		(end 331.382624 -34.02965)
		(width 0.0889)
		(layer "F.Cu")
		(net "IRQ_BMC_PCH_NMI")
	)
	(segment
		(start 332.397608 -38.050216)
		(end 332.397608 -35.044634)
		(width 0.0889)
		(layer "F.Cu")
		(net "IRQ_BMC_PCH_NMI")
	)
	(segment
		(start 330.287376 -29.910024)
		(end 330.13142 -29.533596)
		(width 0.0889)
		(layer "F.Cu")
		(net "IRQ_BMC_PCH_NMI")
	)
	(segment
		(start 330.00696 -20.918932)
		(end 330.348844 -21.260816)
		(width 0.12954)
		(layer "F.Cu")
		(net "IRQ_BMC_PCH_NMI")
	)
	(segment
		(start 330.13142 -29.533596)
		(end 330.13142 -28.786582)
		(width 0.12954)
		(layer "F.Cu")
		(net "IRQ_BMC_PCH_NMI")
	)
	(segment
		(start 330.00696 -20.616926)
		(end 330.00696 -20.918932)
		(width 0.12954)
		(layer "F.Cu")
		(net "IRQ_BMC_PCH_NMI")
	)
	(segment
		(start 330.3778 -24.934164)
		(end 330.805536 -24.506428)
		(width 0.12954)
		(layer "F.Cu")
		(net "IRQ_BMC_PCH_NMI")
	)
	(segment
		(start 330.348844 -21.260816)
		(end 330.348844 -21.625052)
		(width 0.12954)
		(layer "F.Cu")
		(net "IRQ_BMC_PCH_NMI")
	)
	(segment
		(start 330.805536 -24.506428)
		(end 330.805536 -23.950168)
		(width 0.12954)
		(layer "F.Cu")
		(net "IRQ_BMC_PCH_NMI")
	)
	(segment
		(start 330.348844 -21.625052)
		(end 330.348844 -22.243796)
		(width 0.12954)
		(layer "F.Cu")
		(net "IRQ_BMC_PCH_NMI")
	)
	(segment
		(start 330.444856 -22.339808)
		(end 330.444856 -23.117048)
		(width 0.12954)
		(layer "F.Cu")
		(net "IRQ_BMC_PCH_NMI")
	)
	(segment
		(start 331.382624 -31.37535)
		(end 331.03312 -31.025846)
		(width 0.0889)
		(layer "F.Cu")
		(net "IRQ_BMC_PCH_NMI")
	)
	(segment
		(start 331.03312 -31.025846)
		(end 330.287376 -29.910024)
		(width 0.0889)
		(layer "F.Cu")
		(net "IRQ_BMC_PCH_NMI")
	)
	(segment
		(start 330.444856 -23.589488)
		(end 330.444856 -23.117048)
		(width 0.12954)
		(layer "F.Cu")
		(net "IRQ_BMC_PCH_NMI")
	)
	(segment
		(start 331.382624 -34.02965)
		(end 331.382624 -31.37535)
		(width 0.0889)
		(layer "F.Cu")
		(net "IRQ_BMC_PCH_NMI")
	)
	(segment
		(start 330.13142 -28.786582)
		(end 330.3778 -28.191714)
		(width 0.12954)
		(layer "F.Cu")
		(net "IRQ_BMC_PCH_NMI")
	)
	(segment
		(start 330.805536 -23.950168)
		(end 330.444856 -23.589488)
		(width 0.12954)
		(layer "F.Cu")
		(net "IRQ_BMC_PCH_NMI")
	)
	(via
		(at 330.444856 -23.117048)
		(size 0.762)
		(drill 0.381)
		(layers "F.Cu" "B.Cu")
		(net "IRQ_BMC_PCH_NMI")
	)
	(segment
		(start 196.79031 -115.534948)
		(end 196.18071 -115.534948)
		(width 0.12954)
		(layer "F.Cu")
		(net "IRQ_BMC_CPU_NMI_R1")
	)
	(segment
		(start 182.955692 -114.575336)
		(end 183.355742 -114.975386)
		(width 0.12954)
		(layer "F.Cu")
		(net "IRQ_BMC_CPU_NMI_R1")
	)
	(via
		(at 196.18071 -115.534948)
		(size 0.508)
		(drill 0.254)
		(layers "F.Cu" "B.Cu")
		(net "IRQ_BMC_CPU_NMI_R1")
	)
	(via
		(at 183.355742 -114.975386)
		(size 0.4572)
		(drill 0.254)
		(layers "F.Cu" "B.Cu")
		(net "IRQ_BMC_CPU_NMI_R1")
	)
	(segment
		(start 186.817 -114.577368)
		(end 183.75376 -114.577368)
		(width 0.127)
		(layer "In6.Cu")
		(net "IRQ_BMC_CPU_NMI_R1")
	)
	(segment
		(start 196.18071 -115.534948)
		(end 195.44411 -116.271548)
		(width 0.127)
		(layer "In6.Cu")
		(net "IRQ_BMC_CPU_NMI_R1")
	)
	(segment
		(start 183.75376 -114.577368)
		(end 183.355742 -114.975386)
		(width 0.127)
		(layer "In6.Cu")
		(net "IRQ_BMC_CPU_NMI_R1")
	)
	(segment
		(start 193.88582 -116.271548)
		(end 193.024506 -115.410234)
		(width 0.127)
		(layer "In6.Cu")
		(net "IRQ_BMC_CPU_NMI_R1")
	)
	(segment
		(start 193.024506 -115.410234)
		(end 187.649866 -115.410234)
		(width 0.127)
		(layer "In6.Cu")
		(net "IRQ_BMC_CPU_NMI_R1")
	)
	(segment
		(start 195.44411 -116.271548)
		(end 193.88582 -116.271548)
		(width 0.127)
		(layer "In6.Cu")
		(net "IRQ_BMC_CPU_NMI_R1")
	)
	(segment
		(start 187.649866 -115.410234)
		(end 186.817 -114.577368)
		(width 0.127)
		(layer "In6.Cu")
		(net "IRQ_BMC_CPU_NMI_R1")
	)
	(segment
		(start 137.40384 -10.886948)
		(end 137.08888 -10.886948)
		(width 0.12954)
		(layer "F.Cu")
		(net "IRQ0_A57")
	)
	(segment
		(start 138.147044 -13.600176)
		(end 138.147044 -13.599668)
		(width 0.12954)
		(layer "F.Cu")
		(net "IRQ0_A57")
	)
	(segment
		(start 138.156696 -11.639804)
		(end 137.40384 -10.886948)
		(width 0.12954)
		(layer "F.Cu")
		(net "IRQ0_A57")
	)
	(segment
		(start 138.147044 -13.599668)
		(end 138.156696 -13.590016)
		(width 0.12954)
		(layer "F.Cu")
		(net "IRQ0_A57")
	)
	(segment
		(start 138.156696 -13.590016)
		(end 138.156696 -11.639804)
		(width 0.12954)
		(layer "F.Cu")
		(net "IRQ0_A57")
	)
	(via
		(at 137.08888 -10.886948)
		(size 0.508)
		(drill 0.254)
		(layers "F.Cu" "B.Cu")
		(net "IRQ0_A57")
	)
	(segment
		(start 137.08888 -9.762998)
		(end 137.08888 -10.886948)
		(width 0.12954)
		(layer "B.Cu")
		(net "IRQ0_A57")
	)
	(segment
		(start 120.098566 -228.180646)
		(end 120.098566 -227.64496)
		(width 0.12954)
		(layer "F.Cu")
		(net "I3C_SPD_DDREFGH_CPU1_SDA")
	)
	(segment
		(start 120.098312 -228.1809)
		(end 120.098566 -228.180646)
		(width 0.12954)
		(layer "F.Cu")
		(net "I3C_SPD_DDREFGH_CPU1_SDA")
	)
	(via
		(at 120.098566 -227.64496)
		(size 0.4572)
		(drill 0.2032)
		(layers "F.Cu" "B.Cu")
		(net "I3C_SPD_DDREFGH_CPU1_SDA")
	)
	(via
		(at 141.909038 -226.45497)
		(size 0.6604)
		(drill 0.3302)
		(layers "F.Cu" "B.Cu")
		(net "I3C_SPD_DDREFGH_CPU1_SDA")
	)
	(segment
		(start 152.339802 -193.478912)
		(end 152.339802 -190.759334)
		(width 0.12954)
		(layer "B.Cu")
		(net "I3C_SPD_DDREFGH_CPU1_SDA")
	)
	(segment
		(start 127.4191 -227.326698)
		(end 127.429514 -227.320602)
		(width 0.0889)
		(layer "B.Cu")
		(net "I3C_SPD_DDREFGH_CPU1_SDA")
	)
	(segment
		(start 149.983698 -219.143072)
		(end 149.983698 -195.835016)
		(width 0.12954)
		(layer "B.Cu")
		(net "I3C_SPD_DDREFGH_CPU1_SDA")
	)
	(segment
		(start 122.16511 -227.320602)
		(end 122.175524 -227.326698)
		(width 0.0889)
		(layer "B.Cu")
		(net "I3C_SPD_DDREFGH_CPU1_SDA")
	)
	(segment
		(start 131.563364 -227.320602)
		(end 131.578096 -227.329238)
		(width 0.0889)
		(layer "B.Cu")
		(net "I3C_SPD_DDREFGH_CPU1_SDA")
	)
	(segment
		(start 128.354582 -227.329238)
		(end 128.369314 -227.320602)
		(width 0.0889)
		(layer "B.Cu")
		(net "I3C_SPD_DDREFGH_CPU1_SDA")
	)
	(segment
		(start 137.585196 -227.071682)
		(end 138.201908 -226.45497)
		(width 0.12954)
		(layer "B.Cu")
		(net "I3C_SPD_DDREFGH_CPU1_SDA")
	)
	(segment
		(start 153.227278 -190.759334)
		(end 152.339802 -190.759334)
		(width 0.12954)
		(layer "B.Cu")
		(net "I3C_SPD_DDREFGH_CPU1_SDA")
	)
	(segment
		(start 125.924564 -227.320602)
		(end 125.939296 -227.329238)
		(width 0.0889)
		(layer "B.Cu")
		(net "I3C_SPD_DDREFGH_CPU1_SDA")
	)
	(segment
		(start 129.683764 -227.320602)
		(end 129.698496 -227.329238)
		(width 0.0889)
		(layer "B.Cu")
		(net "I3C_SPD_DDREFGH_CPU1_SDA")
	)
	(segment
		(start 120.098566 -227.64496)
		(end 120.25503 -227.373942)
		(width 0.0889)
		(layer "B.Cu")
		(net "I3C_SPD_DDREFGH_CPU1_SDA")
	)
	(segment
		(start 149.983698 -195.835016)
		(end 152.339802 -193.478912)
		(width 0.12954)
		(layer "B.Cu")
		(net "I3C_SPD_DDREFGH_CPU1_SDA")
	)
	(segment
		(start 124.984764 -227.320602)
		(end 124.999496 -227.329238)
		(width 0.0889)
		(layer "B.Cu")
		(net "I3C_SPD_DDREFGH_CPU1_SDA")
	)
	(segment
		(start 153.232104 -190.76416)
		(end 153.227278 -190.759334)
		(width 0.12954)
		(layer "B.Cu")
		(net "I3C_SPD_DDREFGH_CPU1_SDA")
	)
	(segment
		(start 142.6718 -226.45497)
		(end 149.983698 -219.143072)
		(width 0.12954)
		(layer "B.Cu")
		(net "I3C_SPD_DDREFGH_CPU1_SDA")
	)
	(segment
		(start 120.25503 -227.373942)
		(end 120.34393 -227.35032)
		(width 0.0889)
		(layer "B.Cu")
		(net "I3C_SPD_DDREFGH_CPU1_SDA")
	)
	(segment
		(start 138.201908 -226.45497)
		(end 141.909038 -226.45497)
		(width 0.12954)
		(layer "B.Cu")
		(net "I3C_SPD_DDREFGH_CPU1_SDA")
	)
	(segment
		(start 137.05205 -227.276406)
		(end 137.380472 -227.276406)
		(width 0.0889)
		(layer "B.Cu")
		(net "I3C_SPD_DDREFGH_CPU1_SDA")
	)
	(segment
		(start 137.380472 -227.276406)
		(end 137.585196 -227.071682)
		(width 0.0889)
		(layer "B.Cu")
		(net "I3C_SPD_DDREFGH_CPU1_SDA")
	)
	(segment
		(start 128.74371 -227.320602)
		(end 128.754124 -227.326698)
		(width 0.0889)
		(layer "B.Cu")
		(net "I3C_SPD_DDREFGH_CPU1_SDA")
	)
	(segment
		(start 132.503164 -227.320602)
		(end 132.517896 -227.329238)
		(width 0.0889)
		(layer "B.Cu")
		(net "I3C_SPD_DDREFGH_CPU1_SDA")
	)
	(segment
		(start 134.382764 -227.320602)
		(end 134.397496 -227.329238)
		(width 0.0889)
		(layer "B.Cu")
		(net "I3C_SPD_DDREFGH_CPU1_SDA")
	)
	(segment
		(start 123.105164 -227.320602)
		(end 123.119896 -227.329238)
		(width 0.0889)
		(layer "B.Cu")
		(net "I3C_SPD_DDREFGH_CPU1_SDA")
	)
	(segment
		(start 141.909038 -226.45497)
		(end 142.6718 -226.45497)
		(width 0.12954)
		(layer "B.Cu")
		(net "I3C_SPD_DDREFGH_CPU1_SDA")
	)
	(segment
		(start 121.7803 -227.326698)
		(end 121.790714 -227.320602)
		(width 0.0889)
		(layer "B.Cu")
		(net "I3C_SPD_DDREFGH_CPU1_SDA")
	)
	(arc
		(start 131.578096 -227.329238)
		(mid 131.854571 -227.396558)
		(end 132.128768 -227.320602)
		(width 0.0889)
		(layer "B.Cu")
		(net "I3C_SPD_DDREFGH_CPU1_SDA")
	)
	(arc
		(start 121.790714 -227.320602)
		(mid 121.977912 -227.270459)
		(end 122.16511 -227.320602)
		(width 0.0889)
		(layer "B.Cu")
		(net "I3C_SPD_DDREFGH_CPU1_SDA")
	)
	(arc
		(start 124.044964 -227.320602)
		(mid 124.327666 -227.396378)
		(end 124.610368 -227.320602)
		(width 0.0889)
		(layer "B.Cu")
		(net "I3C_SPD_DDREFGH_CPU1_SDA")
	)
	(arc
		(start 134.948168 -227.320602)
		(mid 135.135366 -227.270459)
		(end 135.322564 -227.320602)
		(width 0.0889)
		(layer "B.Cu")
		(net "I3C_SPD_DDREFGH_CPU1_SDA")
	)
	(arc
		(start 131.188968 -227.320602)
		(mid 131.376166 -227.270459)
		(end 131.563364 -227.320602)
		(width 0.0889)
		(layer "B.Cu")
		(net "I3C_SPD_DDREFGH_CPU1_SDA")
	)
	(arc
		(start 122.730768 -227.320602)
		(mid 122.917966 -227.270459)
		(end 123.105164 -227.320602)
		(width 0.0889)
		(layer "B.Cu")
		(net "I3C_SPD_DDREFGH_CPU1_SDA")
	)
	(arc
		(start 129.309368 -227.320602)
		(mid 129.496566 -227.270459)
		(end 129.683764 -227.320602)
		(width 0.0889)
		(layer "B.Cu")
		(net "I3C_SPD_DDREFGH_CPU1_SDA")
	)
	(arc
		(start 120.34393 -227.35032)
		(mid 120.601069 -227.395622)
		(end 120.851168 -227.320602)
		(width 0.0889)
		(layer "B.Cu")
		(net "I3C_SPD_DDREFGH_CPU1_SDA")
	)
	(arc
		(start 132.517896 -227.329238)
		(mid 132.794371 -227.396558)
		(end 133.068568 -227.320602)
		(width 0.0889)
		(layer "B.Cu")
		(net "I3C_SPD_DDREFGH_CPU1_SDA")
	)
	(arc
		(start 134.397496 -227.329238)
		(mid 134.673971 -227.396558)
		(end 134.948168 -227.320602)
		(width 0.0889)
		(layer "B.Cu")
		(net "I3C_SPD_DDREFGH_CPU1_SDA")
	)
	(arc
		(start 125.939296 -227.329238)
		(mid 126.215771 -227.396558)
		(end 126.489968 -227.320602)
		(width 0.0889)
		(layer "B.Cu")
		(net "I3C_SPD_DDREFGH_CPU1_SDA")
	)
	(arc
		(start 135.322564 -227.320602)
		(mid 135.605266 -227.396378)
		(end 135.887968 -227.320602)
		(width 0.0889)
		(layer "B.Cu")
		(net "I3C_SPD_DDREFGH_CPU1_SDA")
	)
	(arc
		(start 133.068568 -227.320602)
		(mid 133.255766 -227.270459)
		(end 133.442964 -227.320602)
		(width 0.0889)
		(layer "B.Cu")
		(net "I3C_SPD_DDREFGH_CPU1_SDA")
	)
	(arc
		(start 133.442964 -227.320602)
		(mid 133.725666 -227.396378)
		(end 134.008368 -227.320602)
		(width 0.0889)
		(layer "B.Cu")
		(net "I3C_SPD_DDREFGH_CPU1_SDA")
	)
	(arc
		(start 136.262364 -227.320602)
		(mid 136.528444 -227.396253)
		(end 136.798558 -227.336604)
		(width 0.0889)
		(layer "B.Cu")
		(net "I3C_SPD_DDREFGH_CPU1_SDA")
	)
	(arc
		(start 123.119896 -227.329238)
		(mid 123.396371 -227.396558)
		(end 123.670568 -227.320602)
		(width 0.0889)
		(layer "B.Cu")
		(net "I3C_SPD_DDREFGH_CPU1_SDA")
	)
	(arc
		(start 129.698496 -227.329238)
		(mid 129.974971 -227.396558)
		(end 130.249168 -227.320602)
		(width 0.0889)
		(layer "B.Cu")
		(net "I3C_SPD_DDREFGH_CPU1_SDA")
	)
	(arc
		(start 130.623564 -227.320602)
		(mid 130.906266 -227.396378)
		(end 131.188968 -227.320602)
		(width 0.0889)
		(layer "B.Cu")
		(net "I3C_SPD_DDREFGH_CPU1_SDA")
	)
	(arc
		(start 120.851168 -227.320602)
		(mid 121.038366 -227.270459)
		(end 121.225564 -227.320602)
		(width 0.0889)
		(layer "B.Cu")
		(net "I3C_SPD_DDREFGH_CPU1_SDA")
	)
	(arc
		(start 128.754124 -227.326698)
		(mid 129.032556 -227.396544)
		(end 129.309368 -227.320602)
		(width 0.0889)
		(layer "B.Cu")
		(net "I3C_SPD_DDREFGH_CPU1_SDA")
	)
	(arc
		(start 132.128768 -227.320602)
		(mid 132.315966 -227.270459)
		(end 132.503164 -227.320602)
		(width 0.0889)
		(layer "B.Cu")
		(net "I3C_SPD_DDREFGH_CPU1_SDA")
	)
	(arc
		(start 121.225564 -227.320602)
		(mid 121.502123 -227.396345)
		(end 121.7803 -227.326698)
		(width 0.0889)
		(layer "B.Cu")
		(net "I3C_SPD_DDREFGH_CPU1_SDA")
	)
	(arc
		(start 130.249168 -227.320602)
		(mid 130.436366 -227.270459)
		(end 130.623564 -227.320602)
		(width 0.0889)
		(layer "B.Cu")
		(net "I3C_SPD_DDREFGH_CPU1_SDA")
	)
	(arc
		(start 134.008368 -227.320602)
		(mid 134.195566 -227.270459)
		(end 134.382764 -227.320602)
		(width 0.0889)
		(layer "B.Cu")
		(net "I3C_SPD_DDREFGH_CPU1_SDA")
	)
	(arc
		(start 124.999496 -227.329238)
		(mid 125.275971 -227.396558)
		(end 125.550168 -227.320602)
		(width 0.0889)
		(layer "B.Cu")
		(net "I3C_SPD_DDREFGH_CPU1_SDA")
	)
	(arc
		(start 123.670568 -227.320602)
		(mid 123.857766 -227.270459)
		(end 124.044964 -227.320602)
		(width 0.0889)
		(layer "B.Cu")
		(net "I3C_SPD_DDREFGH_CPU1_SDA")
	)
	(arc
		(start 124.610368 -227.320602)
		(mid 124.797566 -227.270459)
		(end 124.984764 -227.320602)
		(width 0.0889)
		(layer "B.Cu")
		(net "I3C_SPD_DDREFGH_CPU1_SDA")
	)
	(arc
		(start 125.550168 -227.320602)
		(mid 125.737366 -227.270459)
		(end 125.924564 -227.320602)
		(width 0.0889)
		(layer "B.Cu")
		(net "I3C_SPD_DDREFGH_CPU1_SDA")
	)
	(arc
		(start 127.429514 -227.320602)
		(mid 127.616712 -227.270459)
		(end 127.80391 -227.320602)
		(width 0.0889)
		(layer "B.Cu")
		(net "I3C_SPD_DDREFGH_CPU1_SDA")
	)
	(arc
		(start 127.80391 -227.320602)
		(mid 128.078109 -227.396437)
		(end 128.354582 -227.329238)
		(width 0.0889)
		(layer "B.Cu")
		(net "I3C_SPD_DDREFGH_CPU1_SDA")
	)
	(arc
		(start 136.798558 -227.336604)
		(mid 136.921789 -227.291711)
		(end 137.05205 -227.276406)
		(width 0.0889)
		(layer "B.Cu")
		(net "I3C_SPD_DDREFGH_CPU1_SDA")
	)
	(arc
		(start 122.175524 -227.326698)
		(mid 122.453956 -227.396544)
		(end 122.730768 -227.320602)
		(width 0.0889)
		(layer "B.Cu")
		(net "I3C_SPD_DDREFGH_CPU1_SDA")
	)
	(arc
		(start 135.887968 -227.320602)
		(mid 136.075166 -227.270459)
		(end 136.262364 -227.320602)
		(width 0.0889)
		(layer "B.Cu")
		(net "I3C_SPD_DDREFGH_CPU1_SDA")
	)
	(arc
		(start 126.489968 -227.320602)
		(mid 126.677166 -227.270459)
		(end 126.864364 -227.320602)
		(width 0.0889)
		(layer "B.Cu")
		(net "I3C_SPD_DDREFGH_CPU1_SDA")
	)
	(arc
		(start 126.864364 -227.320602)
		(mid 127.140923 -227.396345)
		(end 127.4191 -227.326698)
		(width 0.0889)
		(layer "B.Cu")
		(net "I3C_SPD_DDREFGH_CPU1_SDA")
	)
	(arc
		(start 128.369314 -227.320602)
		(mid 128.556512 -227.270459)
		(end 128.74371 -227.320602)
		(width 0.0889)
		(layer "B.Cu")
		(net "I3C_SPD_DDREFGH_CPU1_SDA")
	)
	(segment
		(start 120.568212 -227.36683)
		(end 120.568212 -226.831144)
		(width 0.12954)
		(layer "F.Cu")
		(net "I3C_SPD_DDREFGH_CPU1_SCL")
	)
	(segment
		(start 120.568466 -227.367084)
		(end 120.568212 -227.36683)
		(width 0.12954)
		(layer "F.Cu")
		(net "I3C_SPD_DDREFGH_CPU1_SCL")
	)
	(via
		(at 143.957548 -224.07372)
		(size 0.6604)
		(drill 0.3302)
		(layers "F.Cu" "B.Cu")
		(net "I3C_SPD_DDREFGH_CPU1_SCL")
	)
	(via
		(at 120.568212 -226.831144)
		(size 0.4572)
		(drill 0.2032)
		(layers "F.Cu" "B.Cu")
		(net "I3C_SPD_DDREFGH_CPU1_SCL")
	)
	(segment
		(start 133.528054 -227.149406)
		(end 133.538468 -227.155502)
		(width 0.0889)
		(layer "B.Cu")
		(net "I3C_SPD_DDREFGH_CPU1_SCL")
	)
	(segment
		(start 138.140948 -226.01047)
		(end 138.985498 -226.01047)
		(width 0.12954)
		(layer "B.Cu")
		(net "I3C_SPD_DDREFGH_CPU1_SCL")
	)
	(segment
		(start 130.708654 -227.149406)
		(end 130.719068 -227.155502)
		(width 0.0889)
		(layer "B.Cu")
		(net "I3C_SPD_DDREFGH_CPU1_SCL")
	)
	(segment
		(start 121.695464 -227.155502)
		(end 121.705878 -227.149406)
		(width 0.0889)
		(layer "B.Cu")
		(net "I3C_SPD_DDREFGH_CPU1_SCL")
	)
	(segment
		(start 129.764282 -227.146866)
		(end 129.779014 -227.155502)
		(width 0.0889)
		(layer "B.Cu")
		(net "I3C_SPD_DDREFGH_CPU1_SCL")
	)
	(segment
		(start 131.6482 -227.149406)
		(end 131.658614 -227.155502)
		(width 0.0889)
		(layer "B.Cu")
		(net "I3C_SPD_DDREFGH_CPU1_SCL")
	)
	(segment
		(start 151.281638 -193.500756)
		(end 151.281638 -190.75527)
		(width 0.12954)
		(layer "B.Cu")
		(net "I3C_SPD_DDREFGH_CPU1_SCL")
	)
	(segment
		(start 123.185682 -227.146866)
		(end 123.200414 -227.155502)
		(width 0.0889)
		(layer "B.Cu")
		(net "I3C_SPD_DDREFGH_CPU1_SCL")
	)
	(segment
		(start 149.221698 -195.560696)
		(end 151.281638 -193.500756)
		(width 0.12954)
		(layer "B.Cu")
		(net "I3C_SPD_DDREFGH_CPU1_SCL")
	)
	(segment
		(start 126.949454 -227.149406)
		(end 126.959868 -227.155502)
		(width 0.0889)
		(layer "B.Cu")
		(net "I3C_SPD_DDREFGH_CPU1_SCL")
	)
	(segment
		(start 150.396194 -190.75527)
		(end 151.281638 -190.75527)
		(width 0.12954)
		(layer "B.Cu")
		(net "I3C_SPD_DDREFGH_CPU1_SCL")
	)
	(segment
		(start 143.957548 -224.07372)
		(end 149.221698 -218.80957)
		(width 0.12954)
		(layer "B.Cu")
		(net "I3C_SPD_DDREFGH_CPU1_SCL")
	)
	(segment
		(start 140.164058 -224.83191)
		(end 143.199358 -224.83191)
		(width 0.12954)
		(layer "B.Cu")
		(net "I3C_SPD_DDREFGH_CPU1_SCL")
	)
	(segment
		(start 137.07364 -227.077016)
		(end 137.074402 -227.077016)
		(width 0.0889)
		(layer "B.Cu")
		(net "I3C_SPD_DDREFGH_CPU1_SCL")
	)
	(segment
		(start 120.411748 -227.102162)
		(end 120.43283 -227.18014)
		(width 0.0889)
		(layer "B.Cu")
		(net "I3C_SPD_DDREFGH_CPU1_SCL")
	)
	(segment
		(start 132.583682 -227.146866)
		(end 132.598414 -227.155502)
		(width 0.0889)
		(layer "B.Cu")
		(net "I3C_SPD_DDREFGH_CPU1_SCL")
	)
	(segment
		(start 138.985498 -226.01047)
		(end 140.164058 -224.83191)
		(width 0.12954)
		(layer "B.Cu")
		(net "I3C_SPD_DDREFGH_CPU1_SCL")
	)
	(segment
		(start 137.074402 -227.077016)
		(end 137.393426 -226.757992)
		(width 0.0889)
		(layer "B.Cu")
		(net "I3C_SPD_DDREFGH_CPU1_SCL")
	)
	(segment
		(start 150.387304 -190.76416)
		(end 150.396194 -190.75527)
		(width 0.12954)
		(layer "B.Cu")
		(net "I3C_SPD_DDREFGH_CPU1_SCL")
	)
	(segment
		(start 137.393426 -226.757992)
		(end 138.140948 -226.01047)
		(width 0.12954)
		(layer "B.Cu")
		(net "I3C_SPD_DDREFGH_CPU1_SCL")
	)
	(segment
		(start 126.005082 -227.146866)
		(end 126.019814 -227.155502)
		(width 0.0889)
		(layer "B.Cu")
		(net "I3C_SPD_DDREFGH_CPU1_SCL")
	)
	(segment
		(start 127.334264 -227.155502)
		(end 127.348996 -227.146866)
		(width 0.0889)
		(layer "B.Cu")
		(net "I3C_SPD_DDREFGH_CPU1_SCL")
	)
	(segment
		(start 128.274064 -227.155502)
		(end 128.284478 -227.149406)
		(width 0.0889)
		(layer "B.Cu")
		(net "I3C_SPD_DDREFGH_CPU1_SCL")
	)
	(segment
		(start 149.221698 -218.80957)
		(end 149.221698 -195.560696)
		(width 0.12954)
		(layer "B.Cu")
		(net "I3C_SPD_DDREFGH_CPU1_SCL")
	)
	(segment
		(start 120.568212 -226.831144)
		(end 120.411748 -227.102162)
		(width 0.0889)
		(layer "B.Cu")
		(net "I3C_SPD_DDREFGH_CPU1_SCL")
	)
	(segment
		(start 125.0696 -227.149406)
		(end 125.080014 -227.155502)
		(width 0.0889)
		(layer "B.Cu")
		(net "I3C_SPD_DDREFGH_CPU1_SCL")
	)
	(segment
		(start 135.407654 -227.149406)
		(end 135.418068 -227.155502)
		(width 0.0889)
		(layer "B.Cu")
		(net "I3C_SPD_DDREFGH_CPU1_SCL")
	)
	(segment
		(start 121.310654 -227.149406)
		(end 121.321068 -227.155502)
		(width 0.0889)
		(layer "B.Cu")
		(net "I3C_SPD_DDREFGH_CPU1_SCL")
	)
	(segment
		(start 124.130054 -227.149406)
		(end 124.140468 -227.155502)
		(width 0.0889)
		(layer "B.Cu")
		(net "I3C_SPD_DDREFGH_CPU1_SCL")
	)
	(segment
		(start 134.4676 -227.149406)
		(end 134.478014 -227.155502)
		(width 0.0889)
		(layer "B.Cu")
		(net "I3C_SPD_DDREFGH_CPU1_SCL")
	)
	(segment
		(start 143.199358 -224.83191)
		(end 143.957548 -224.07372)
		(width 0.12954)
		(layer "B.Cu")
		(net "I3C_SPD_DDREFGH_CPU1_SCL")
	)
	(arc
		(start 133.912864 -227.155502)
		(mid 134.189423 -227.079759)
		(end 134.4676 -227.149406)
		(width 0.0889)
		(layer "B.Cu")
		(net "I3C_SPD_DDREFGH_CPU1_SCL")
	)
	(arc
		(start 124.140468 -227.155502)
		(mid 124.327666 -227.205645)
		(end 124.514864 -227.155502)
		(width 0.0889)
		(layer "B.Cu")
		(net "I3C_SPD_DDREFGH_CPU1_SCL")
	)
	(arc
		(start 132.03301 -227.155502)
		(mid 132.307209 -227.079667)
		(end 132.583682 -227.146866)
		(width 0.0889)
		(layer "B.Cu")
		(net "I3C_SPD_DDREFGH_CPU1_SCL")
	)
	(arc
		(start 126.39421 -227.155502)
		(mid 126.671023 -227.079632)
		(end 126.949454 -227.149406)
		(width 0.0889)
		(layer "B.Cu")
		(net "I3C_SPD_DDREFGH_CPU1_SCL")
	)
	(arc
		(start 136.965944 -227.081588)
		(mid 137.019744 -227.078161)
		(end 137.07364 -227.077016)
		(width 0.0889)
		(layer "B.Cu")
		(net "I3C_SPD_DDREFGH_CPU1_SCL")
	)
	(arc
		(start 134.85241 -227.155502)
		(mid 135.129223 -227.079632)
		(end 135.407654 -227.149406)
		(width 0.0889)
		(layer "B.Cu")
		(net "I3C_SPD_DDREFGH_CPU1_SCL")
	)
	(arc
		(start 136.732264 -227.155502)
		(mid 136.845052 -227.10574)
		(end 136.965944 -227.081588)
		(width 0.0889)
		(layer "B.Cu")
		(net "I3C_SPD_DDREFGH_CPU1_SCL")
	)
	(arc
		(start 122.260614 -227.155502)
		(mid 122.447812 -227.205645)
		(end 122.63501 -227.155502)
		(width 0.0889)
		(layer "B.Cu")
		(net "I3C_SPD_DDREFGH_CPU1_SCL")
	)
	(arc
		(start 135.792464 -227.155502)
		(mid 136.075166 -227.079726)
		(end 136.357868 -227.155502)
		(width 0.0889)
		(layer "B.Cu")
		(net "I3C_SPD_DDREFGH_CPU1_SCL")
	)
	(arc
		(start 129.21361 -227.155502)
		(mid 129.487809 -227.079667)
		(end 129.764282 -227.146866)
		(width 0.0889)
		(layer "B.Cu")
		(net "I3C_SPD_DDREFGH_CPU1_SCL")
	)
	(arc
		(start 134.478014 -227.155502)
		(mid 134.665212 -227.205645)
		(end 134.85241 -227.155502)
		(width 0.0889)
		(layer "B.Cu")
		(net "I3C_SPD_DDREFGH_CPU1_SCL")
	)
	(arc
		(start 125.45441 -227.155502)
		(mid 125.728609 -227.079667)
		(end 126.005082 -227.146866)
		(width 0.0889)
		(layer "B.Cu")
		(net "I3C_SPD_DDREFGH_CPU1_SCL")
	)
	(arc
		(start 130.15341 -227.155502)
		(mid 130.430223 -227.079632)
		(end 130.708654 -227.149406)
		(width 0.0889)
		(layer "B.Cu")
		(net "I3C_SPD_DDREFGH_CPU1_SCL")
	)
	(arc
		(start 131.658614 -227.155502)
		(mid 131.845812 -227.205645)
		(end 132.03301 -227.155502)
		(width 0.0889)
		(layer "B.Cu")
		(net "I3C_SPD_DDREFGH_CPU1_SCL")
	)
	(arc
		(start 120.75541 -227.155502)
		(mid 121.032223 -227.079632)
		(end 121.310654 -227.149406)
		(width 0.0889)
		(layer "B.Cu")
		(net "I3C_SPD_DDREFGH_CPU1_SCL")
	)
	(arc
		(start 122.63501 -227.155502)
		(mid 122.909209 -227.079667)
		(end 123.185682 -227.146866)
		(width 0.0889)
		(layer "B.Cu")
		(net "I3C_SPD_DDREFGH_CPU1_SCL")
	)
	(arc
		(start 128.839214 -227.155502)
		(mid 129.026412 -227.205645)
		(end 129.21361 -227.155502)
		(width 0.0889)
		(layer "B.Cu")
		(net "I3C_SPD_DDREFGH_CPU1_SCL")
	)
	(arc
		(start 127.899668 -227.155502)
		(mid 128.086866 -227.205645)
		(end 128.274064 -227.155502)
		(width 0.0889)
		(layer "B.Cu")
		(net "I3C_SPD_DDREFGH_CPU1_SCL")
	)
	(arc
		(start 132.598414 -227.155502)
		(mid 132.785612 -227.205645)
		(end 132.97281 -227.155502)
		(width 0.0889)
		(layer "B.Cu")
		(net "I3C_SPD_DDREFGH_CPU1_SCL")
	)
	(arc
		(start 126.019814 -227.155502)
		(mid 126.207012 -227.205645)
		(end 126.39421 -227.155502)
		(width 0.0889)
		(layer "B.Cu")
		(net "I3C_SPD_DDREFGH_CPU1_SCL")
	)
	(arc
		(start 126.959868 -227.155502)
		(mid 127.147066 -227.205645)
		(end 127.334264 -227.155502)
		(width 0.0889)
		(layer "B.Cu")
		(net "I3C_SPD_DDREFGH_CPU1_SCL")
	)
	(arc
		(start 120.43283 -227.18014)
		(mid 120.596926 -227.204487)
		(end 120.75541 -227.155502)
		(width 0.0889)
		(layer "B.Cu")
		(net "I3C_SPD_DDREFGH_CPU1_SCL")
	)
	(arc
		(start 132.97281 -227.155502)
		(mid 133.249623 -227.079632)
		(end 133.528054 -227.149406)
		(width 0.0889)
		(layer "B.Cu")
		(net "I3C_SPD_DDREFGH_CPU1_SCL")
	)
	(arc
		(start 121.321068 -227.155502)
		(mid 121.508266 -227.205645)
		(end 121.695464 -227.155502)
		(width 0.0889)
		(layer "B.Cu")
		(net "I3C_SPD_DDREFGH_CPU1_SCL")
	)
	(arc
		(start 121.705878 -227.149406)
		(mid 121.984056 -227.079683)
		(end 122.260614 -227.155502)
		(width 0.0889)
		(layer "B.Cu")
		(net "I3C_SPD_DDREFGH_CPU1_SCL")
	)
	(arc
		(start 123.200414 -227.155502)
		(mid 123.387612 -227.205645)
		(end 123.57481 -227.155502)
		(width 0.0889)
		(layer "B.Cu")
		(net "I3C_SPD_DDREFGH_CPU1_SCL")
	)
	(arc
		(start 123.57481 -227.155502)
		(mid 123.851623 -227.079632)
		(end 124.130054 -227.149406)
		(width 0.0889)
		(layer "B.Cu")
		(net "I3C_SPD_DDREFGH_CPU1_SCL")
	)
	(arc
		(start 131.093464 -227.155502)
		(mid 131.370023 -227.079759)
		(end 131.6482 -227.149406)
		(width 0.0889)
		(layer "B.Cu")
		(net "I3C_SPD_DDREFGH_CPU1_SCL")
	)
	(arc
		(start 128.284478 -227.149406)
		(mid 128.562656 -227.079683)
		(end 128.839214 -227.155502)
		(width 0.0889)
		(layer "B.Cu")
		(net "I3C_SPD_DDREFGH_CPU1_SCL")
	)
	(arc
		(start 127.348996 -227.146866)
		(mid 127.625471 -227.079546)
		(end 127.899668 -227.155502)
		(width 0.0889)
		(layer "B.Cu")
		(net "I3C_SPD_DDREFGH_CPU1_SCL")
	)
	(arc
		(start 136.357868 -227.155502)
		(mid 136.545066 -227.205645)
		(end 136.732264 -227.155502)
		(width 0.0889)
		(layer "B.Cu")
		(net "I3C_SPD_DDREFGH_CPU1_SCL")
	)
	(arc
		(start 129.779014 -227.155502)
		(mid 129.966212 -227.205645)
		(end 130.15341 -227.155502)
		(width 0.0889)
		(layer "B.Cu")
		(net "I3C_SPD_DDREFGH_CPU1_SCL")
	)
	(arc
		(start 133.538468 -227.155502)
		(mid 133.725666 -227.205645)
		(end 133.912864 -227.155502)
		(width 0.0889)
		(layer "B.Cu")
		(net "I3C_SPD_DDREFGH_CPU1_SCL")
	)
	(arc
		(start 124.514864 -227.155502)
		(mid 124.791423 -227.079759)
		(end 125.0696 -227.149406)
		(width 0.0889)
		(layer "B.Cu")
		(net "I3C_SPD_DDREFGH_CPU1_SCL")
	)
	(arc
		(start 135.418068 -227.155502)
		(mid 135.605266 -227.205645)
		(end 135.792464 -227.155502)
		(width 0.0889)
		(layer "B.Cu")
		(net "I3C_SPD_DDREFGH_CPU1_SCL")
	)
	(arc
		(start 125.080014 -227.155502)
		(mid 125.267212 -227.205645)
		(end 125.45441 -227.155502)
		(width 0.0889)
		(layer "B.Cu")
		(net "I3C_SPD_DDREFGH_CPU1_SCL")
	)
	(arc
		(start 130.719068 -227.155502)
		(mid 130.906266 -227.205645)
		(end 131.093464 -227.155502)
		(width 0.0889)
		(layer "B.Cu")
		(net "I3C_SPD_DDREFGH_CPU1_SCL")
	)
	(segment
		(start 81.542636 -148.630132)
		(end 80.91424 -149.258528)
		(width 0.12954)
		(layer "F.Cu")
		(net "I3C_SPD_DDREFGH_CPU1_R_SDA")
	)
	(segment
		(start 81.05648 -149.400768)
		(end 81.05648 -151.048212)
		(width 0.12954)
		(layer "F.Cu")
		(net "I3C_SPD_DDREFGH_CPU1_R_SDA")
	)
	(segment
		(start 81.05648 -151.048212)
		(end 80.7212 -151.383492)
		(width 0.12954)
		(layer "F.Cu")
		(net "I3C_SPD_DDREFGH_CPU1_R_SDA")
	)
	(segment
		(start 80.91424 -149.258528)
		(end 81.05648 -149.400768)
		(width 0.12954)
		(layer "F.Cu")
		(net "I3C_SPD_DDREFGH_CPU1_R_SDA")
	)
	(segment
		(start 82.384138 -148.630132)
		(end 81.542636 -148.630132)
		(width 0.12954)
		(layer "F.Cu")
		(net "I3C_SPD_DDREFGH_CPU1_R_SDA")
	)
	(via
		(at 153.232104 -188.30925)
		(size 0.508)
		(drill 0.254)
		(layers "F.Cu" "B.Cu")
		(net "I3C_SPD_DDREFGH_CPU1_R_SDA")
	)
	(via
		(at 80.91424 -149.258528)
		(size 0.508)
		(drill 0.254)
		(layers "F.Cu" "B.Cu")
		(net "I3C_SPD_DDREFGH_CPU1_R_SDA")
	)
	(segment
		(start 153.232104 -189.96406)
		(end 153.232104 -188.30925)
		(width 0.12954)
		(layer "B.Cu")
		(net "I3C_SPD_DDREFGH_CPU1_R_SDA")
	)
	(segment
		(start 86.18728 -183.987948)
		(end 85.47354 -183.274208)
		(width 0.127)
		(layer "In13.Cu")
		(net "I3C_SPD_DDREFGH_CPU1_R_SDA")
	)
	(segment
		(start 86.82228 -188.344048)
		(end 86.82228 -187.112148)
		(width 0.127)
		(layer "In13.Cu")
		(net "I3C_SPD_DDREFGH_CPU1_R_SDA")
	)
	(segment
		(start 85.47354 -183.274208)
		(end 83.52028 -183.274208)
		(width 0.127)
		(layer "In13.Cu")
		(net "I3C_SPD_DDREFGH_CPU1_R_SDA")
	)
	(segment
		(start 83.52028 -183.274208)
		(end 81.33842 -181.092348)
		(width 0.127)
		(layer "In13.Cu")
		(net "I3C_SPD_DDREFGH_CPU1_R_SDA")
	)
	(segment
		(start 82.45348 -150.383748)
		(end 81.32826 -149.258528)
		(width 0.127)
		(layer "In13.Cu")
		(net "I3C_SPD_DDREFGH_CPU1_R_SDA")
	)
	(segment
		(start 87.50808 -189.029848)
		(end 86.82228 -188.344048)
		(width 0.127)
		(layer "In13.Cu")
		(net "I3C_SPD_DDREFGH_CPU1_R_SDA")
	)
	(segment
		(start 81.33842 -181.092348)
		(end 81.33842 -153.894028)
		(width 0.127)
		(layer "In13.Cu")
		(net "I3C_SPD_DDREFGH_CPU1_R_SDA")
	)
	(segment
		(start 81.32826 -149.258528)
		(end 80.91424 -149.258528)
		(width 0.127)
		(layer "In13.Cu")
		(net "I3C_SPD_DDREFGH_CPU1_R_SDA")
	)
	(segment
		(start 90.635836 -190.960248)
		(end 88.705436 -189.029848)
		(width 0.127)
		(layer "In13.Cu")
		(net "I3C_SPD_DDREFGH_CPU1_R_SDA")
	)
	(segment
		(start 82.45348 -152.778968)
		(end 82.45348 -150.383748)
		(width 0.127)
		(layer "In13.Cu")
		(net "I3C_SPD_DDREFGH_CPU1_R_SDA")
	)
	(segment
		(start 153.232104 -188.30925)
		(end 153.232104 -189.775084)
		(width 0.127)
		(layer "In13.Cu")
		(net "I3C_SPD_DDREFGH_CPU1_R_SDA")
	)
	(segment
		(start 86.82228 -187.112148)
		(end 86.18728 -186.477148)
		(width 0.127)
		(layer "In13.Cu")
		(net "I3C_SPD_DDREFGH_CPU1_R_SDA")
	)
	(segment
		(start 88.705436 -189.029848)
		(end 87.50808 -189.029848)
		(width 0.127)
		(layer "In13.Cu")
		(net "I3C_SPD_DDREFGH_CPU1_R_SDA")
	)
	(segment
		(start 152.04694 -190.960248)
		(end 90.635836 -190.960248)
		(width 0.127)
		(layer "In13.Cu")
		(net "I3C_SPD_DDREFGH_CPU1_R_SDA")
	)
	(segment
		(start 81.33842 -153.894028)
		(end 82.45348 -152.778968)
		(width 0.127)
		(layer "In13.Cu")
		(net "I3C_SPD_DDREFGH_CPU1_R_SDA")
	)
	(segment
		(start 86.18728 -186.477148)
		(end 86.18728 -183.987948)
		(width 0.127)
		(layer "In13.Cu")
		(net "I3C_SPD_DDREFGH_CPU1_R_SDA")
	)
	(segment
		(start 153.232104 -189.775084)
		(end 152.04694 -190.960248)
		(width 0.127)
		(layer "In13.Cu")
		(net "I3C_SPD_DDREFGH_CPU1_R_SDA")
	)
	(segment
		(start 81.15808 -146.725132)
		(end 80.953864 -146.725132)
		(width 0.12954)
		(layer "F.Cu")
		(net "I3C_SPD_DDREFGH_CPU1_R_SCL")
	)
	(segment
		(start 80.12176 -144.050004)
		(end 81.12506 -143.046704)
		(width 0.12954)
		(layer "F.Cu")
		(net "I3C_SPD_DDREFGH_CPU1_R_SCL")
	)
	(segment
		(start 80.12176 -145.893028)
		(end 80.12176 -144.050004)
		(width 0.12954)
		(layer "F.Cu")
		(net "I3C_SPD_DDREFGH_CPU1_R_SCL")
	)
	(segment
		(start 80.953864 -146.725132)
		(end 80.12176 -145.893028)
		(width 0.12954)
		(layer "F.Cu")
		(net "I3C_SPD_DDREFGH_CPU1_R_SCL")
	)
	(segment
		(start 82.384138 -146.725132)
		(end 81.15808 -146.725132)
		(width 0.12954)
		(layer "F.Cu")
		(net "I3C_SPD_DDREFGH_CPU1_R_SCL")
	)
	(segment
		(start 81.12506 -143.046704)
		(end 81.33842 -143.046704)
		(width 0.12954)
		(layer "F.Cu")
		(net "I3C_SPD_DDREFGH_CPU1_R_SCL")
	)
	(via
		(at 150.45436 -189.134496)
		(size 0.508)
		(drill 0.254)
		(layers "F.Cu" "B.Cu")
		(net "I3C_SPD_DDREFGH_CPU1_R_SCL")
	)
	(via
		(at 81.15808 -146.725132)
		(size 0.508)
		(drill 0.254)
		(layers "F.Cu" "B.Cu")
		(net "I3C_SPD_DDREFGH_CPU1_R_SCL")
	)
	(segment
		(start 150.45436 -189.897004)
		(end 150.387304 -189.96406)
		(width 0.12954)
		(layer "B.Cu")
		(net "I3C_SPD_DDREFGH_CPU1_R_SCL")
	)
	(segment
		(start 150.45436 -189.134496)
		(end 150.45436 -189.897004)
		(width 0.12954)
		(layer "B.Cu")
		(net "I3C_SPD_DDREFGH_CPU1_R_SCL")
	)
	(segment
		(start 150.132034 -190.289688)
		(end 90.91422 -190.289688)
		(width 0.127)
		(layer "In13.Cu")
		(net "I3C_SPD_DDREFGH_CPU1_R_SCL")
	)
	(segment
		(start 150.45436 -189.967362)
		(end 150.132034 -190.289688)
		(width 0.127)
		(layer "In13.Cu")
		(net "I3C_SPD_DDREFGH_CPU1_R_SCL")
	)
	(segment
		(start 81.484724 -146.725132)
		(end 81.15808 -146.725132)
		(width 0.127)
		(layer "In13.Cu")
		(net "I3C_SPD_DDREFGH_CPU1_R_SCL")
	)
	(segment
		(start 83.88604 -182.588408)
		(end 82.00898 -180.711348)
		(width 0.127)
		(layer "In13.Cu")
		(net "I3C_SPD_DDREFGH_CPU1_R_SCL")
	)
	(segment
		(start 87.00008 -183.810148)
		(end 85.77834 -182.588408)
		(width 0.127)
		(layer "In13.Cu")
		(net "I3C_SPD_DDREFGH_CPU1_R_SCL")
	)
	(segment
		(start 85.77834 -182.588408)
		(end 83.88604 -182.588408)
		(width 0.127)
		(layer "In13.Cu")
		(net "I3C_SPD_DDREFGH_CPU1_R_SCL")
	)
	(segment
		(start 82.00898 -154.137868)
		(end 83.12404 -153.022808)
		(width 0.127)
		(layer "In13.Cu")
		(net "I3C_SPD_DDREFGH_CPU1_R_SCL")
	)
	(segment
		(start 83.12404 -148.364448)
		(end 81.484724 -146.725132)
		(width 0.127)
		(layer "In13.Cu")
		(net "I3C_SPD_DDREFGH_CPU1_R_SCL")
	)
	(segment
		(start 150.45436 -189.134496)
		(end 150.45436 -189.967362)
		(width 0.127)
		(layer "In13.Cu")
		(net "I3C_SPD_DDREFGH_CPU1_R_SCL")
	)
	(segment
		(start 83.12404 -153.022808)
		(end 83.12404 -148.364448)
		(width 0.127)
		(layer "In13.Cu")
		(net "I3C_SPD_DDREFGH_CPU1_R_SCL")
	)
	(segment
		(start 87.00008 -186.375548)
		(end 87.00008 -183.810148)
		(width 0.127)
		(layer "In13.Cu")
		(net "I3C_SPD_DDREFGH_CPU1_R_SCL")
	)
	(segment
		(start 90.91422 -190.289688)
		(end 87.00008 -186.375548)
		(width 0.127)
		(layer "In13.Cu")
		(net "I3C_SPD_DDREFGH_CPU1_R_SCL")
	)
	(segment
		(start 82.00898 -180.711348)
		(end 82.00898 -154.137868)
		(width 0.127)
		(layer "In13.Cu")
		(net "I3C_SPD_DDREFGH_CPU1_R_SCL")
	)
	(segment
		(start 171.230798 -318.44107)
		(end 171.456858 -318.44107)
		(width 0.12954)
		(layer "F.Cu")
		(net "I3C_SPD_DDREFGH_CPU1_LVC1_SDA")
	)
	(segment
		(start 169.629836 -318.446912)
		(end 169.635678 -318.44107)
		(width 0.12954)
		(layer "F.Cu")
		(net "I3C_SPD_DDREFGH_CPU1_LVC1_SDA")
	)
	(segment
		(start 195.000118 -318.016636)
		(end 196.532246 -318.016636)
		(width 0.12954)
		(layer "F.Cu")
		(net "I3C_SPD_DDREFGH_CPU1_LVC1_SDA")
	)
	(segment
		(start 186.371738 -317.590932)
		(end 186.842146 -317.590932)
		(width 0.12954)
		(layer "F.Cu")
		(net "I3C_SPD_DDREFGH_CPU1_LVC1_SDA")
	)
	(segment
		(start 187.26785 -318.016636)
		(end 188.988446 -318.016636)
		(width 0.12954)
		(layer "F.Cu")
		(net "I3C_SPD_DDREFGH_CPU1_LVC1_SDA")
	)
	(segment
		(start 163.732718 -317.590932)
		(end 163.847526 -317.590932)
		(width 0.12954)
		(layer "F.Cu")
		(net "I3C_SPD_DDREFGH_CPU1_LVC1_SDA")
	)
	(segment
		(start 179.867814 -317.590932)
		(end 180.293518 -318.016636)
		(width 0.12954)
		(layer "F.Cu")
		(net "I3C_SPD_DDREFGH_CPU1_LVC1_SDA")
	)
	(segment
		(start 188.988446 -318.016636)
		(end 190.971932 -318.016636)
		(width 0.12954)
		(layer "F.Cu")
		(net "I3C_SPD_DDREFGH_CPU1_LVC1_SDA")
	)
	(segment
		(start 158.813246 -318.016636)
		(end 160.990026 -318.016636)
		(width 0.12954)
		(layer "F.Cu")
		(net "I3C_SPD_DDREFGH_CPU1_LVC1_SDA")
	)
	(segment
		(start 202.632818 -318.016636)
		(end 204.076046 -318.016636)
		(width 0.12954)
		(layer "F.Cu")
		(net "I3C_SPD_DDREFGH_CPU1_LVC1_SDA")
	)
	(segment
		(start 205.566772 -318.016636)
		(end 204.076046 -318.016636)
		(width 0.12954)
		(layer "F.Cu")
		(net "I3C_SPD_DDREFGH_CPU1_LVC1_SDA")
	)
	(segment
		(start 211.619846 -318.016636)
		(end 210.21421 -318.016636)
		(width 0.12954)
		(layer "F.Cu")
		(net "I3C_SPD_DDREFGH_CPU1_LVC1_SDA")
	)
	(segment
		(start 183.209692 -318.016636)
		(end 183.635396 -317.590932)
		(width 0.12954)
		(layer "F.Cu")
		(net "I3C_SPD_DDREFGH_CPU1_LVC1_SDA")
	)
	(segment
		(start 171.881292 -318.016636)
		(end 173.900846 -318.016636)
		(width 0.12954)
		(layer "F.Cu")
		(net "I3C_SPD_DDREFGH_CPU1_LVC1_SDA")
	)
	(segment
		(start 199.810878 -317.590932)
		(end 201.469498 -317.590932)
		(width 0.1016)
		(layer "F.Cu")
		(net "I3C_SPD_DDREFGH_CPU1_LVC1_SDA")
	)
	(segment
		(start 176.958498 -317.590932)
		(end 178.853338 -317.590932)
		(width 0.1016)
		(layer "F.Cu")
		(net "I3C_SPD_DDREFGH_CPU1_LVC1_SDA")
	)
	(segment
		(start 180.293518 -318.016636)
		(end 181.444646 -318.016636)
		(width 0.12954)
		(layer "F.Cu")
		(net "I3C_SPD_DDREFGH_CPU1_LVC1_SDA")
	)
	(segment
		(start 210.21421 -318.016636)
		(end 209.788506 -317.590932)
		(width 0.12954)
		(layer "F.Cu")
		(net "I3C_SPD_DDREFGH_CPU1_LVC1_SDA")
	)
	(segment
		(start 209.788506 -317.590932)
		(end 208.985358 -317.590932)
		(width 0.12954)
		(layer "F.Cu")
		(net "I3C_SPD_DDREFGH_CPU1_LVC1_SDA")
	)
	(segment
		(start 213.536276 -317.590932)
		(end 213.110572 -318.016636)
		(width 0.12954)
		(layer "F.Cu")
		(net "I3C_SPD_DDREFGH_CPU1_LVC1_SDA")
	)
	(segment
		(start 192.267078 -317.590932)
		(end 193.918078 -317.590932)
		(width 0.1016)
		(layer "F.Cu")
		(net "I3C_SPD_DDREFGH_CPU1_LVC1_SDA")
	)
	(segment
		(start 216.529158 -317.590932)
		(end 214.898478 -317.590932)
		(width 0.1016)
		(layer "F.Cu")
		(net "I3C_SPD_DDREFGH_CPU1_LVC1_SDA")
	)
	(segment
		(start 160.990026 -318.016636)
		(end 161.41573 -317.590932)
		(width 0.12954)
		(layer "F.Cu")
		(net "I3C_SPD_DDREFGH_CPU1_LVC1_SDA")
	)
	(segment
		(start 198.109332 -318.016636)
		(end 198.535036 -317.590932)
		(width 0.12954)
		(layer "F.Cu")
		(net "I3C_SPD_DDREFGH_CPU1_LVC1_SDA")
	)
	(segment
		(start 184.723278 -317.590932)
		(end 186.371738 -317.590932)
		(width 0.1016)
		(layer "F.Cu")
		(net "I3C_SPD_DDREFGH_CPU1_LVC1_SDA")
	)
	(segment
		(start 208.985358 -317.590932)
		(end 207.354678 -317.590932)
		(width 0.1016)
		(layer "F.Cu")
		(net "I3C_SPD_DDREFGH_CPU1_LVC1_SDA")
	)
	(segment
		(start 214.898478 -317.590932)
		(end 213.536276 -317.590932)
		(width 0.12954)
		(layer "F.Cu")
		(net "I3C_SPD_DDREFGH_CPU1_LVC1_SDA")
	)
	(segment
		(start 191.397636 -317.590932)
		(end 192.267078 -317.590932)
		(width 0.12954)
		(layer "F.Cu")
		(net "I3C_SPD_DDREFGH_CPU1_LVC1_SDA")
	)
	(segment
		(start 216.976198 -317.590932)
		(end 216.529158 -317.590932)
		(width 0.12954)
		(layer "F.Cu")
		(net "I3C_SPD_DDREFGH_CPU1_LVC1_SDA")
	)
	(segment
		(start 80.71866 -153.658316)
		(end 80.71866 -152.381204)
		(width 0.12954)
		(layer "F.Cu")
		(net "I3C_SPD_DDREFGH_CPU1_LVC1_SDA")
	)
	(segment
		(start 190.971932 -318.016636)
		(end 191.397636 -317.590932)
		(width 0.12954)
		(layer "F.Cu")
		(net "I3C_SPD_DDREFGH_CPU1_LVC1_SDA")
	)
	(segment
		(start 178.853338 -317.590932)
		(end 179.867814 -317.590932)
		(width 0.12954)
		(layer "F.Cu")
		(net "I3C_SPD_DDREFGH_CPU1_LVC1_SDA")
	)
	(segment
		(start 201.469498 -317.590932)
		(end 202.207114 -317.590932)
		(width 0.12954)
		(layer "F.Cu")
		(net "I3C_SPD_DDREFGH_CPU1_LVC1_SDA")
	)
	(segment
		(start 81.340452 -154.280108)
		(end 80.71866 -153.658316)
		(width 0.12954)
		(layer "F.Cu")
		(net "I3C_SPD_DDREFGH_CPU1_LVC1_SDA")
	)
	(segment
		(start 196.532246 -318.016636)
		(end 198.109332 -318.016636)
		(width 0.12954)
		(layer "F.Cu")
		(net "I3C_SPD_DDREFGH_CPU1_LVC1_SDA")
	)
	(segment
		(start 168.383204 -318.016636)
		(end 168.81348 -318.446912)
		(width 0.12954)
		(layer "F.Cu")
		(net "I3C_SPD_DDREFGH_CPU1_LVC1_SDA")
	)
	(segment
		(start 205.992476 -317.590932)
		(end 205.566772 -318.016636)
		(width 0.12954)
		(layer "F.Cu")
		(net "I3C_SPD_DDREFGH_CPU1_LVC1_SDA")
	)
	(segment
		(start 186.842146 -317.590932)
		(end 187.26785 -318.016636)
		(width 0.12954)
		(layer "F.Cu")
		(net "I3C_SPD_DDREFGH_CPU1_LVC1_SDA")
	)
	(segment
		(start 162.091878 -317.590932)
		(end 163.732718 -317.590932)
		(width 0.1016)
		(layer "F.Cu")
		(net "I3C_SPD_DDREFGH_CPU1_LVC1_SDA")
	)
	(segment
		(start 83.5787 -154.280108)
		(end 81.340452 -154.280108)
		(width 0.12954)
		(layer "F.Cu")
		(net "I3C_SPD_DDREFGH_CPU1_LVC1_SDA")
	)
	(segment
		(start 166.357046 -318.016636)
		(end 168.383204 -318.016636)
		(width 0.12954)
		(layer "F.Cu")
		(net "I3C_SPD_DDREFGH_CPU1_LVC1_SDA")
	)
	(segment
		(start 181.444646 -318.016636)
		(end 183.209692 -318.016636)
		(width 0.12954)
		(layer "F.Cu")
		(net "I3C_SPD_DDREFGH_CPU1_LVC1_SDA")
	)
	(segment
		(start 207.354678 -317.590932)
		(end 205.992476 -317.590932)
		(width 0.12954)
		(layer "F.Cu")
		(net "I3C_SPD_DDREFGH_CPU1_LVC1_SDA")
	)
	(segment
		(start 163.847526 -317.590932)
		(end 164.27323 -318.016636)
		(width 0.12954)
		(layer "F.Cu")
		(net "I3C_SPD_DDREFGH_CPU1_LVC1_SDA")
	)
	(segment
		(start 171.456858 -318.44107)
		(end 171.881292 -318.016636)
		(width 0.12954)
		(layer "F.Cu")
		(net "I3C_SPD_DDREFGH_CPU1_LVC1_SDA")
	)
	(segment
		(start 168.81348 -318.446912)
		(end 169.629836 -318.446912)
		(width 0.12954)
		(layer "F.Cu")
		(net "I3C_SPD_DDREFGH_CPU1_LVC1_SDA")
	)
	(segment
		(start 164.27323 -318.016636)
		(end 166.357046 -318.016636)
		(width 0.12954)
		(layer "F.Cu")
		(net "I3C_SPD_DDREFGH_CPU1_LVC1_SDA")
	)
	(segment
		(start 213.110572 -318.016636)
		(end 211.619846 -318.016636)
		(width 0.12954)
		(layer "F.Cu")
		(net "I3C_SPD_DDREFGH_CPU1_LVC1_SDA")
	)
	(segment
		(start 193.918078 -317.590932)
		(end 194.574414 -317.590932)
		(width 0.12954)
		(layer "F.Cu")
		(net "I3C_SPD_DDREFGH_CPU1_LVC1_SDA")
	)
	(segment
		(start 194.574414 -317.590932)
		(end 195.000118 -318.016636)
		(width 0.12954)
		(layer "F.Cu")
		(net "I3C_SPD_DDREFGH_CPU1_LVC1_SDA")
	)
	(segment
		(start 161.41573 -317.590932)
		(end 162.091878 -317.590932)
		(width 0.12954)
		(layer "F.Cu")
		(net "I3C_SPD_DDREFGH_CPU1_LVC1_SDA")
	)
	(segment
		(start 175.119538 -318.016636)
		(end 175.545242 -317.590932)
		(width 0.12954)
		(layer "F.Cu")
		(net "I3C_SPD_DDREFGH_CPU1_LVC1_SDA")
	)
	(segment
		(start 169.635678 -318.44107)
		(end 171.230798 -318.44107)
		(width 0.1016)
		(layer "F.Cu")
		(net "I3C_SPD_DDREFGH_CPU1_LVC1_SDA")
	)
	(segment
		(start 202.207114 -317.590932)
		(end 202.632818 -318.016636)
		(width 0.12954)
		(layer "F.Cu")
		(net "I3C_SPD_DDREFGH_CPU1_LVC1_SDA")
	)
	(segment
		(start 183.635396 -317.590932)
		(end 184.723278 -317.590932)
		(width 0.12954)
		(layer "F.Cu")
		(net "I3C_SPD_DDREFGH_CPU1_LVC1_SDA")
	)
	(segment
		(start 175.545242 -317.590932)
		(end 176.958498 -317.590932)
		(width 0.12954)
		(layer "F.Cu")
		(net "I3C_SPD_DDREFGH_CPU1_LVC1_SDA")
	)
	(segment
		(start 198.535036 -317.590932)
		(end 199.810878 -317.590932)
		(width 0.12954)
		(layer "F.Cu")
		(net "I3C_SPD_DDREFGH_CPU1_LVC1_SDA")
	)
	(segment
		(start 173.900846 -318.016636)
		(end 175.119538 -318.016636)
		(width 0.12954)
		(layer "F.Cu")
		(net "I3C_SPD_DDREFGH_CPU1_LVC1_SDA")
	)
	(via
		(at 219.62872 -190.901828)
		(size 0.508)
		(drill 0.254)
		(layers "F.Cu" "B.Cu")
		(net "I3C_SPD_DDREFGH_CPU1_LVC1_SDA")
	)
	(via
		(at 216.976198 -317.590932)
		(size 0.508)
		(drill 0.254)
		(layers "F.Cu" "B.Cu")
		(net "I3C_SPD_DDREFGH_CPU1_LVC1_SDA")
	)
	(via
		(at 83.5787 -154.280108)
		(size 0.508)
		(drill 0.254)
		(layers "F.Cu" "B.Cu")
		(net "I3C_SPD_DDREFGH_CPU1_LVC1_SDA")
	)
	(segment
		(start 218.8464 -191.684148)
		(end 218.8464 -215.49995)
		(width 0.127)
		(layer "In2.Cu")
		(net "I3C_SPD_DDREFGH_CPU1_LVC1_SDA")
	)
	(segment
		(start 218.8464 -215.49995)
		(end 218.10218 -216.24417)
		(width 0.127)
		(layer "In2.Cu")
		(net "I3C_SPD_DDREFGH_CPU1_LVC1_SDA")
	)
	(segment
		(start 218.10218 -316.46495)
		(end 216.976198 -317.590932)
		(width 0.127)
		(layer "In2.Cu")
		(net "I3C_SPD_DDREFGH_CPU1_LVC1_SDA")
	)
	(segment
		(start 219.62872 -190.901828)
		(end 218.8464 -191.684148)
		(width 0.127)
		(layer "In2.Cu")
		(net "I3C_SPD_DDREFGH_CPU1_LVC1_SDA")
	)
	(segment
		(start 218.10218 -216.24417)
		(end 218.10218 -316.46495)
		(width 0.127)
		(layer "In2.Cu")
		(net "I3C_SPD_DDREFGH_CPU1_LVC1_SDA")
	)
	(segment
		(start 219.62872 -190.901828)
		(end 211.8995 -183.172608)
		(width 0.127)
		(layer "In13.Cu")
		(net "I3C_SPD_DDREFGH_CPU1_LVC1_SDA")
	)
	(segment
		(start 89.82964 -175.994568)
		(end 89.309448 -175.994568)
		(width 0.127)
		(layer "In13.Cu")
		(net "I3C_SPD_DDREFGH_CPU1_LVC1_SDA")
	)
	(segment
		(start 89.309448 -175.994568)
		(end 83.90128 -170.5864)
		(width 0.127)
		(layer "In13.Cu")
		(net "I3C_SPD_DDREFGH_CPU1_LVC1_SDA")
	)
	(segment
		(start 97.00768 -183.172608)
		(end 89.82964 -175.994568)
		(width 0.127)
		(layer "In13.Cu")
		(net "I3C_SPD_DDREFGH_CPU1_LVC1_SDA")
	)
	(segment
		(start 83.90128 -170.5864)
		(end 83.90128 -154.602688)
		(width 0.127)
		(layer "In13.Cu")
		(net "I3C_SPD_DDREFGH_CPU1_LVC1_SDA")
	)
	(segment
		(start 211.8995 -183.172608)
		(end 97.00768 -183.172608)
		(width 0.127)
		(layer "In13.Cu")
		(net "I3C_SPD_DDREFGH_CPU1_LVC1_SDA")
	)
	(segment
		(start 83.90128 -154.602688)
		(end 83.5787 -154.280108)
		(width 0.127)
		(layer "In13.Cu")
		(net "I3C_SPD_DDREFGH_CPU1_LVC1_SDA")
	)
	(segment
		(start 80.376776 -142.01775)
		(end 81.315814 -142.01775)
		(width 0.12954)
		(layer "F.Cu")
		(net "I3C_SPD_DDREFGH_CPU1_LVC1_SCL")
	)
	(segment
		(start 81.315814 -142.01775)
		(end 81.339436 -142.041372)
		(width 0.12954)
		(layer "F.Cu")
		(net "I3C_SPD_DDREFGH_CPU1_LVC1_SCL")
	)
	(via
		(at 212.85708 -313.037728)
		(size 0.508)
		(drill 0.254)
		(layers "F.Cu" "B.Cu")
		(net "I3C_SPD_DDREFGH_CPU1_LVC1_SCL")
	)
	(via
		(at 183.75884 -316.390528)
		(size 0.508)
		(drill 0.254)
		(layers "F.Cu" "B.Cu")
		(net "I3C_SPD_DDREFGH_CPU1_LVC1_SCL")
	)
	(via
		(at 80.376776 -142.01775)
		(size 0.508)
		(drill 0.254)
		(layers "F.Cu" "B.Cu")
		(net "I3C_SPD_DDREFGH_CPU1_LVC1_SCL")
	)
	(via
		(at 218.3003 -190.617348)
		(size 0.508)
		(drill 0.254)
		(layers "F.Cu" "B.Cu")
		(net "I3C_SPD_DDREFGH_CPU1_LVC1_SCL")
	)
	(via
		(at 190.72606 -317.119)
		(size 0.4572)
		(drill 0.2032)
		(layers "F.Cu" "B.Cu")
		(net "I3C_SPD_DDREFGH_CPU1_LVC1_SCL")
	)
	(segment
		(start 172.18406 -317.203074)
		(end 172.18406 -315.85535)
		(width 0.12954)
		(layer "B.Cu")
		(net "I3C_SPD_DDREFGH_CPU1_LVC1_SCL")
	)
	(segment
		(start 190.073788 -316.466728)
		(end 190.72606 -317.119)
		(width 0.12954)
		(layer "B.Cu")
		(net "I3C_SPD_DDREFGH_CPU1_LVC1_SCL")
	)
	(segment
		(start 179.44973 -316.845188)
		(end 178.849274 -316.845188)
		(width 0.12954)
		(layer "B.Cu")
		(net "I3C_SPD_DDREFGH_CPU1_LVC1_SCL")
	)
	(segment
		(start 179.75961 -316.535308)
		(end 179.44973 -316.845188)
		(width 0.12954)
		(layer "B.Cu")
		(net "I3C_SPD_DDREFGH_CPU1_LVC1_SCL")
	)
	(segment
		(start 173.940216 -317.08979)
		(end 173.91507 -317.08979)
		(width 0.12954)
		(layer "B.Cu")
		(net "I3C_SPD_DDREFGH_CPU1_LVC1_SCL")
	)
	(segment
		(start 181.114192 -316.865)
		(end 180.7845 -316.535308)
		(width 0.12954)
		(layer "B.Cu")
		(net "I3C_SPD_DDREFGH_CPU1_LVC1_SCL")
	)
	(segment
		(start 176.185322 -316.203076)
		(end 174.82693 -316.203076)
		(width 0.12954)
		(layer "B.Cu")
		(net "I3C_SPD_DDREFGH_CPU1_LVC1_SCL")
	)
	(segment
		(start 168.677844 -315.539628)
		(end 168.025064 -316.192408)
		(width 0.12954)
		(layer "B.Cu")
		(net "I3C_SPD_DDREFGH_CPU1_LVC1_SCL")
	)
	(segment
		(start 177.868834 -315.864748)
		(end 176.52365 -315.864748)
		(width 0.12954)
		(layer "B.Cu")
		(net "I3C_SPD_DDREFGH_CPU1_LVC1_SCL")
	)
	(segment
		(start 203.991464 -315.986668)
		(end 203.925424 -315.920628)
		(width 0.12954)
		(layer "B.Cu")
		(net "I3C_SPD_DDREFGH_CPU1_LVC1_SCL")
	)
	(segment
		(start 206.630778 -315.986668)
		(end 203.991464 -315.986668)
		(width 0.12954)
		(layer "B.Cu")
		(net "I3C_SPD_DDREFGH_CPU1_LVC1_SCL")
	)
	(segment
		(start 208.30794 -314.696348)
		(end 208.30794 -315.858398)
		(width 0.12954)
		(layer "B.Cu")
		(net "I3C_SPD_DDREFGH_CPU1_LVC1_SCL")
	)
	(segment
		(start 209.96656 -313.037728)
		(end 208.30794 -314.696348)
		(width 0.12954)
		(layer "B.Cu")
		(net "I3C_SPD_DDREFGH_CPU1_LVC1_SCL")
	)
	(segment
		(start 172.18406 -315.85535)
		(end 171.868338 -315.539628)
		(width 0.12954)
		(layer "B.Cu")
		(net "I3C_SPD_DDREFGH_CPU1_LVC1_SCL")
	)
	(segment
		(start 191.527938 -315.869828)
		(end 191.257936 -316.13983)
		(width 0.12954)
		(layer "B.Cu")
		(net "I3C_SPD_DDREFGH_CPU1_LVC1_SCL")
	)
	(segment
		(start 166.102538 -316.255654)
		(end 165.087554 -316.255654)
		(width 0.12954)
		(layer "B.Cu")
		(net "I3C_SPD_DDREFGH_CPU1_LVC1_SCL")
	)
	(segment
		(start 178.849274 -316.845188)
		(end 177.868834 -315.864748)
		(width 0.12954)
		(layer "B.Cu")
		(net "I3C_SPD_DDREFGH_CPU1_LVC1_SCL")
	)
	(segment
		(start 173.91507 -317.08979)
		(end 173.30674 -317.69812)
		(width 0.12954)
		(layer "B.Cu")
		(net "I3C_SPD_DDREFGH_CPU1_LVC1_SCL")
	)
	(segment
		(start 164.413692 -315.581792)
		(end 161.3916 -315.581792)
		(width 0.12954)
		(layer "B.Cu")
		(net "I3C_SPD_DDREFGH_CPU1_LVC1_SCL")
	)
	(segment
		(start 160.570164 -316.403228)
		(end 158.980378 -316.403228)
		(width 0.12954)
		(layer "B.Cu")
		(net "I3C_SPD_DDREFGH_CPU1_LVC1_SCL")
	)
	(segment
		(start 183.67756 -316.309248)
		(end 182.65394 -316.309248)
		(width 0.12954)
		(layer "B.Cu")
		(net "I3C_SPD_DDREFGH_CPU1_LVC1_SCL")
	)
	(segment
		(start 188.981588 -316.466728)
		(end 190.073788 -316.466728)
		(width 0.12954)
		(layer "B.Cu")
		(net "I3C_SPD_DDREFGH_CPU1_LVC1_SCL")
	)
	(segment
		(start 192.917572 -315.869828)
		(end 191.527938 -315.869828)
		(width 0.12954)
		(layer "B.Cu")
		(net "I3C_SPD_DDREFGH_CPU1_LVC1_SCL")
	)
	(segment
		(start 180.7845 -316.535308)
		(end 179.75961 -316.535308)
		(width 0.12954)
		(layer "B.Cu")
		(net "I3C_SPD_DDREFGH_CPU1_LVC1_SCL")
	)
	(segment
		(start 182.65394 -316.309248)
		(end 182.098188 -316.865)
		(width 0.12954)
		(layer "B.Cu")
		(net "I3C_SPD_DDREFGH_CPU1_LVC1_SCL")
	)
	(segment
		(start 212.85708 -313.037728)
		(end 209.96656 -313.037728)
		(width 0.12954)
		(layer "B.Cu")
		(net "I3C_SPD_DDREFGH_CPU1_LVC1_SCL")
	)
	(segment
		(start 208.30794 -315.858398)
		(end 206.759048 -315.858398)
		(width 0.12954)
		(layer "B.Cu")
		(net "I3C_SPD_DDREFGH_CPU1_LVC1_SCL")
	)
	(segment
		(start 196.23278 -316.467998)
		(end 195.17868 -316.467998)
		(width 0.12954)
		(layer "B.Cu")
		(net "I3C_SPD_DDREFGH_CPU1_LVC1_SCL")
	)
	(segment
		(start 183.75884 -316.390528)
		(end 183.67756 -316.309248)
		(width 0.12954)
		(layer "B.Cu")
		(net "I3C_SPD_DDREFGH_CPU1_LVC1_SCL")
	)
	(segment
		(start 158.980378 -316.403228)
		(end 158.297118 -317.086488)
		(width 0.12954)
		(layer "B.Cu")
		(net "I3C_SPD_DDREFGH_CPU1_LVC1_SCL")
	)
	(segment
		(start 202.668124 -315.920628)
		(end 202.381866 -315.63437)
		(width 0.12954)
		(layer "B.Cu")
		(net "I3C_SPD_DDREFGH_CPU1_LVC1_SCL")
	)
	(segment
		(start 193.948812 -316.901068)
		(end 192.917572 -315.869828)
		(width 0.12954)
		(layer "B.Cu")
		(net "I3C_SPD_DDREFGH_CPU1_LVC1_SCL")
	)
	(segment
		(start 198.252588 -316.467998)
		(end 196.23278 -316.467998)
		(width 0.12954)
		(layer "B.Cu")
		(net "I3C_SPD_DDREFGH_CPU1_LVC1_SCL")
	)
	(segment
		(start 202.381866 -315.63437)
		(end 199.086216 -315.63437)
		(width 0.12954)
		(layer "B.Cu")
		(net "I3C_SPD_DDREFGH_CPU1_LVC1_SCL")
	)
	(segment
		(start 165.087554 -316.255654)
		(end 164.413692 -315.581792)
		(width 0.12954)
		(layer "B.Cu")
		(net "I3C_SPD_DDREFGH_CPU1_LVC1_SCL")
	)
	(segment
		(start 182.098188 -316.865)
		(end 181.464458 -316.865)
		(width 0.12954)
		(layer "B.Cu")
		(net "I3C_SPD_DDREFGH_CPU1_LVC1_SCL")
	)
	(segment
		(start 173.30674 -317.69812)
		(end 172.679106 -317.69812)
		(width 0.12954)
		(layer "B.Cu")
		(net "I3C_SPD_DDREFGH_CPU1_LVC1_SCL")
	)
	(segment
		(start 161.3916 -315.581792)
		(end 160.570164 -316.403228)
		(width 0.12954)
		(layer "B.Cu")
		(net "I3C_SPD_DDREFGH_CPU1_LVC1_SCL")
	)
	(segment
		(start 203.925424 -315.920628)
		(end 202.668124 -315.920628)
		(width 0.12954)
		(layer "B.Cu")
		(net "I3C_SPD_DDREFGH_CPU1_LVC1_SCL")
	)
	(segment
		(start 199.086216 -315.63437)
		(end 198.252588 -316.467998)
		(width 0.12954)
		(layer "B.Cu")
		(net "I3C_SPD_DDREFGH_CPU1_LVC1_SCL")
	)
	(segment
		(start 158.297118 -317.086488)
		(end 158.297118 -318.336422)
		(width 0.12954)
		(layer "B.Cu")
		(net "I3C_SPD_DDREFGH_CPU1_LVC1_SCL")
	)
	(segment
		(start 181.464458 -316.865)
		(end 181.114192 -316.865)
		(width 0.12954)
		(layer "B.Cu")
		(net "I3C_SPD_DDREFGH_CPU1_LVC1_SCL")
	)
	(segment
		(start 191.257936 -316.587124)
		(end 190.72606 -317.119)
		(width 0.12954)
		(layer "B.Cu")
		(net "I3C_SPD_DDREFGH_CPU1_LVC1_SCL")
	)
	(segment
		(start 206.759048 -315.858398)
		(end 206.630778 -315.986668)
		(width 0.12954)
		(layer "B.Cu")
		(net "I3C_SPD_DDREFGH_CPU1_LVC1_SCL")
	)
	(segment
		(start 174.82693 -316.203076)
		(end 173.940216 -317.08979)
		(width 0.12954)
		(layer "B.Cu")
		(net "I3C_SPD_DDREFGH_CPU1_LVC1_SCL")
	)
	(segment
		(start 166.165784 -316.192408)
		(end 166.102538 -316.255654)
		(width 0.12954)
		(layer "B.Cu")
		(net "I3C_SPD_DDREFGH_CPU1_LVC1_SCL")
	)
	(segment
		(start 195.17868 -316.467998)
		(end 194.74561 -316.901068)
		(width 0.12954)
		(layer "B.Cu")
		(net "I3C_SPD_DDREFGH_CPU1_LVC1_SCL")
	)
	(segment
		(start 176.52365 -315.864748)
		(end 176.185322 -316.203076)
		(width 0.12954)
		(layer "B.Cu")
		(net "I3C_SPD_DDREFGH_CPU1_LVC1_SCL")
	)
	(segment
		(start 194.74561 -316.901068)
		(end 193.948812 -316.901068)
		(width 0.12954)
		(layer "B.Cu")
		(net "I3C_SPD_DDREFGH_CPU1_LVC1_SCL")
	)
	(segment
		(start 168.025064 -316.192408)
		(end 166.165784 -316.192408)
		(width 0.12954)
		(layer "B.Cu")
		(net "I3C_SPD_DDREFGH_CPU1_LVC1_SCL")
	)
	(segment
		(start 172.679106 -317.69812)
		(end 172.18406 -317.203074)
		(width 0.12954)
		(layer "B.Cu")
		(net "I3C_SPD_DDREFGH_CPU1_LVC1_SCL")
	)
	(segment
		(start 191.257936 -316.13983)
		(end 191.257936 -316.587124)
		(width 0.12954)
		(layer "B.Cu")
		(net "I3C_SPD_DDREFGH_CPU1_LVC1_SCL")
	)
	(segment
		(start 171.868338 -315.539628)
		(end 168.677844 -315.539628)
		(width 0.12954)
		(layer "B.Cu")
		(net "I3C_SPD_DDREFGH_CPU1_LVC1_SCL")
	)
	(segment
		(start 216.70518 -313.527948)
		(end 216.3572 -313.179968)
		(width 0.127)
		(layer "In2.Cu")
		(net "I3C_SPD_DDREFGH_CPU1_LVC1_SCL")
	)
	(segment
		(start 184.220866 -317.678308)
		(end 183.75884 -317.216282)
		(width 0.127)
		(layer "In2.Cu")
		(net "I3C_SPD_DDREFGH_CPU1_LVC1_SCL")
	)
	(segment
		(start 190.72606 -317.19266)
		(end 190.085472 -317.833248)
		(width 0.127)
		(layer "In2.Cu")
		(net "I3C_SPD_DDREFGH_CPU1_LVC1_SCL")
	)
	(segment
		(start 213.7156 -313.037728)
		(end 212.85708 -313.037728)
		(width 0.127)
		(layer "In2.Cu")
		(net "I3C_SPD_DDREFGH_CPU1_LVC1_SCL")
	)
	(segment
		(start 214.06104 -313.383168)
		(end 213.7156 -313.037728)
		(width 0.127)
		(layer "In2.Cu")
		(net "I3C_SPD_DDREFGH_CPU1_LVC1_SCL")
	)
	(segment
		(start 187.459366 -317.748158)
		(end 187.082176 -317.370968)
		(width 0.127)
		(layer "In2.Cu")
		(net "I3C_SPD_DDREFGH_CPU1_LVC1_SCL")
	)
	(segment
		(start 216.3572 -313.179968)
		(end 215.10244 -313.179968)
		(width 0.127)
		(layer "In2.Cu")
		(net "I3C_SPD_DDREFGH_CPU1_LVC1_SCL")
	)
	(segment
		(start 217.422222 -215.767666)
		(end 217.422222 -313.136026)
		(width 0.127)
		(layer "In2.Cu")
		(net "I3C_SPD_DDREFGH_CPU1_LVC1_SCL")
	)
	(segment
		(start 187.664852 -317.833248)
		(end 187.459366 -317.748158)
		(width 0.127)
		(layer "In2.Cu")
		(net "I3C_SPD_DDREFGH_CPU1_LVC1_SCL")
	)
	(segment
		(start 190.72606 -317.119)
		(end 190.72606 -317.19266)
		(width 0.127)
		(layer "In2.Cu")
		(net "I3C_SPD_DDREFGH_CPU1_LVC1_SCL")
	)
	(segment
		(start 218.20124 -214.988648)
		(end 217.422222 -215.767666)
		(width 0.127)
		(layer "In2.Cu")
		(net "I3C_SPD_DDREFGH_CPU1_LVC1_SCL")
	)
	(segment
		(start 217.422222 -313.136026)
		(end 217.0303 -313.527948)
		(width 0.127)
		(layer "In2.Cu")
		(net "I3C_SPD_DDREFGH_CPU1_LVC1_SCL")
	)
	(segment
		(start 214.89924 -313.383168)
		(end 214.06104 -313.383168)
		(width 0.127)
		(layer "In2.Cu")
		(net "I3C_SPD_DDREFGH_CPU1_LVC1_SCL")
	)
	(segment
		(start 183.75884 -317.216282)
		(end 183.75884 -316.390528)
		(width 0.127)
		(layer "In2.Cu")
		(net "I3C_SPD_DDREFGH_CPU1_LVC1_SCL")
	)
	(segment
		(start 217.0303 -313.527948)
		(end 216.70518 -313.527948)
		(width 0.127)
		(layer "In2.Cu")
		(net "I3C_SPD_DDREFGH_CPU1_LVC1_SCL")
	)
	(segment
		(start 185.05678 -317.678308)
		(end 184.220866 -317.678308)
		(width 0.127)
		(layer "In2.Cu")
		(net "I3C_SPD_DDREFGH_CPU1_LVC1_SCL")
	)
	(segment
		(start 218.20124 -190.716408)
		(end 218.20124 -214.988648)
		(width 0.127)
		(layer "In2.Cu")
		(net "I3C_SPD_DDREFGH_CPU1_LVC1_SCL")
	)
	(segment
		(start 215.10244 -313.179968)
		(end 214.89924 -313.383168)
		(width 0.127)
		(layer "In2.Cu")
		(net "I3C_SPD_DDREFGH_CPU1_LVC1_SCL")
	)
	(segment
		(start 218.3003 -190.617348)
		(end 218.20124 -190.716408)
		(width 0.127)
		(layer "In2.Cu")
		(net "I3C_SPD_DDREFGH_CPU1_LVC1_SCL")
	)
	(segment
		(start 190.085472 -317.833248)
		(end 187.664852 -317.833248)
		(width 0.127)
		(layer "In2.Cu")
		(net "I3C_SPD_DDREFGH_CPU1_LVC1_SCL")
	)
	(segment
		(start 187.082176 -317.370968)
		(end 185.798968 -317.370968)
		(width 0.127)
		(layer "In2.Cu")
		(net "I3C_SPD_DDREFGH_CPU1_LVC1_SCL")
	)
	(segment
		(start 185.798968 -317.370968)
		(end 185.05678 -317.678308)
		(width 0.127)
		(layer "In2.Cu")
		(net "I3C_SPD_DDREFGH_CPU1_LVC1_SCL")
	)
	(segment
		(start 89.656158 -176.722786)
		(end 89.139522 -176.722786)
		(width 0.127)
		(layer "In13.Cu")
		(net "I3C_SPD_DDREFGH_CPU1_LVC1_SCL")
	)
	(segment
		(start 83.81238 -153.266648)
		(end 83.81238 -145.453354)
		(width 0.127)
		(layer "In13.Cu")
		(net "I3C_SPD_DDREFGH_CPU1_LVC1_SCL")
	)
	(segment
		(start 82.72272 -154.356308)
		(end 83.81238 -153.266648)
		(width 0.127)
		(layer "In13.Cu")
		(net "I3C_SPD_DDREFGH_CPU1_LVC1_SCL")
	)
	(segment
		(start 96.76892 -183.835548)
		(end 89.656158 -176.722786)
		(width 0.127)
		(layer "In13.Cu")
		(net "I3C_SPD_DDREFGH_CPU1_LVC1_SCL")
	)
	(segment
		(start 83.23834 -156.017468)
		(end 82.72272 -155.501848)
		(width 0.127)
		(layer "In13.Cu")
		(net "I3C_SPD_DDREFGH_CPU1_LVC1_SCL")
	)
	(segment
		(start 211.5185 -183.835548)
		(end 96.76892 -183.835548)
		(width 0.127)
		(layer "In13.Cu")
		(net "I3C_SPD_DDREFGH_CPU1_LVC1_SCL")
	)
	(segment
		(start 82.72272 -155.501848)
		(end 82.72272 -154.356308)
		(width 0.127)
		(layer "In13.Cu")
		(net "I3C_SPD_DDREFGH_CPU1_LVC1_SCL")
	)
	(segment
		(start 83.23834 -170.821604)
		(end 83.23834 -156.017468)
		(width 0.127)
		(layer "In13.Cu")
		(net "I3C_SPD_DDREFGH_CPU1_LVC1_SCL")
	)
	(segment
		(start 218.3003 -190.617348)
		(end 211.5185 -183.835548)
		(width 0.127)
		(layer "In13.Cu")
		(net "I3C_SPD_DDREFGH_CPU1_LVC1_SCL")
	)
	(segment
		(start 89.139522 -176.722786)
		(end 83.23834 -170.821604)
		(width 0.127)
		(layer "In13.Cu")
		(net "I3C_SPD_DDREFGH_CPU1_LVC1_SCL")
	)
	(segment
		(start 83.81238 -145.453354)
		(end 80.376776 -142.01775)
		(width 0.127)
		(layer "In13.Cu")
		(net "I3C_SPD_DDREFGH_CPU1_LVC1_SCL")
	)
	(segment
		(start 79.91856 -151.386032)
		(end 79.91856 -152.381204)
		(width 0.12954)
		(layer "F.Cu")
		(net "I3C_SPD_DDREFGH_CPU1_LVC1_R_SDA")
	)
	(segment
		(start 79.9211 -151.383492)
		(end 79.91856 -151.386032)
		(width 0.12954)
		(layer "F.Cu")
		(net "I3C_SPD_DDREFGH_CPU1_LVC1_R_SDA")
	)
	(segment
		(start 80.296258 -150.56739)
		(end 80.296258 -147.83435)
		(width 0.12954)
		(layer "F.Cu")
		(net "I3C_SPD_DDREFGH_CPU1_LVC1_R_SDA")
	)
	(segment
		(start 79.9211 -150.942548)
		(end 80.296258 -150.56739)
		(width 0.12954)
		(layer "F.Cu")
		(net "I3C_SPD_DDREFGH_CPU1_LVC1_R_SDA")
	)
	(segment
		(start 80.296258 -147.83435)
		(end 80.770476 -147.360132)
		(width 0.12954)
		(layer "F.Cu")
		(net "I3C_SPD_DDREFGH_CPU1_LVC1_R_SDA")
	)
	(segment
		(start 79.9211 -151.383492)
		(end 79.9211 -150.942548)
		(width 0.12954)
		(layer "F.Cu")
		(net "I3C_SPD_DDREFGH_CPU1_LVC1_R_SDA")
	)
	(segment
		(start 80.770476 -147.360132)
		(end 82.384138 -147.360132)
		(width 0.12954)
		(layer "F.Cu")
		(net "I3C_SPD_DDREFGH_CPU1_LVC1_R_SDA")
	)
	(via
		(at 80.296258 -150.56739)
		(size 0.508)
		(drill 0.254)
		(layers "F.Cu" "B.Cu")
		(net "I3C_SPD_DDREFGH_CPU1_LVC1_R_SDA")
	)
	(segment
		(start 82.13852 -143.046704)
		(end 82.13852 -142.042388)
		(width 0.12954)
		(layer "F.Cu")
		(net "I3C_SPD_DDREFGH_CPU1_LVC1_R_SCL")
	)
	(segment
		(start 81.17586 -144.248124)
		(end 81.17586 -144.862042)
		(width 0.12954)
		(layer "F.Cu")
		(net "I3C_SPD_DDREFGH_CPU1_LVC1_R_SCL")
	)
	(segment
		(start 82.13852 -142.042388)
		(end 82.139536 -142.041372)
		(width 0.12954)
		(layer "F.Cu")
		(net "I3C_SPD_DDREFGH_CPU1_LVC1_R_SCL")
	)
	(segment
		(start 82.13852 -143.046704)
		(end 81.17586 -144.009364)
		(width 0.12954)
		(layer "F.Cu")
		(net "I3C_SPD_DDREFGH_CPU1_LVC1_R_SCL")
	)
	(segment
		(start 81.17586 -144.862042)
		(end 81.76895 -145.455132)
		(width 0.12954)
		(layer "F.Cu")
		(net "I3C_SPD_DDREFGH_CPU1_LVC1_R_SCL")
	)
	(segment
		(start 81.76895 -145.455132)
		(end 82.384138 -145.455132)
		(width 0.12954)
		(layer "F.Cu")
		(net "I3C_SPD_DDREFGH_CPU1_LVC1_R_SCL")
	)
	(segment
		(start 81.17586 -144.009364)
		(end 81.17586 -144.248124)
		(width 0.12954)
		(layer "F.Cu")
		(net "I3C_SPD_DDREFGH_CPU1_LVC1_R_SCL")
	)
	(via
		(at 81.17586 -144.248124)
		(size 0.762)
		(drill 0.381)
		(layers "F.Cu" "B.Cu")
		(net "I3C_SPD_DDREFGH_CPU1_LVC1_R_SCL")
	)
	(segment
		(start 82.384138 -147.995132)
		(end 81.15808 -147.995132)
		(width 0.12954)
		(layer "F.Cu")
		(net "I3C_SPD_DDREFGH_CPU1_BMC_SDA")
	)
	(via
		(at 182.867046 -14.950948)
		(size 0.508)
		(drill 0.254)
		(layers "F.Cu" "B.Cu")
		(net "I3C_SPD_DDREFGH_CPU1_BMC_SDA")
	)
	(via
		(at 81.15808 -147.995132)
		(size 0.508)
		(drill 0.254)
		(layers "F.Cu" "B.Cu")
		(net "I3C_SPD_DDREFGH_CPU1_BMC_SDA")
	)
	(segment
		(start 182.867046 -14.00048)
		(end 182.867046 -14.950948)
		(width 0.12954)
		(layer "B.Cu")
		(net "I3C_SPD_DDREFGH_CPU1_BMC_SDA")
	)
	(segment
		(start 141.470888 -23.86584)
		(end 136.730232 -23.86584)
		(width 0.127)
		(layer "In4.Cu")
		(net "I3C_SPD_DDREFGH_CPU1_BMC_SDA")
	)
	(segment
		(start 79.72552 -147.147788)
		(end 80.572864 -147.995132)
		(width 0.127)
		(layer "In4.Cu")
		(net "I3C_SPD_DDREFGH_CPU1_BMC_SDA")
	)
	(segment
		(start 79.72552 -134.85368)
		(end 79.72552 -147.147788)
		(width 0.127)
		(layer "In4.Cu")
		(net "I3C_SPD_DDREFGH_CPU1_BMC_SDA")
	)
	(segment
		(start 88.616536 -44.731432)
		(end 81.82356 -51.524408)
		(width 0.127)
		(layer "In4.Cu")
		(net "I3C_SPD_DDREFGH_CPU1_BMC_SDA")
	)
	(segment
		(start 127.12954 -25.504648)
		(end 116.841524 -35.792664)
		(width 0.127)
		(layer "In4.Cu")
		(net "I3C_SPD_DDREFGH_CPU1_BMC_SDA")
	)
	(segment
		(start 146.595592 -22.189948)
		(end 143.14678 -22.189948)
		(width 0.127)
		(layer "In4.Cu")
		(net "I3C_SPD_DDREFGH_CPU1_BMC_SDA")
	)
	(segment
		(start 158.623 -15.458948)
		(end 153.326592 -15.458948)
		(width 0.127)
		(layer "In4.Cu")
		(net "I3C_SPD_DDREFGH_CPU1_BMC_SDA")
	)
	(segment
		(start 127.12954 -24.162512)
		(end 127.12954 -25.504648)
		(width 0.127)
		(layer "In4.Cu")
		(net "I3C_SPD_DDREFGH_CPU1_BMC_SDA")
	)
	(segment
		(start 181.345586 -13.429488)
		(end 160.740344 -13.429488)
		(width 0.127)
		(layer "In4.Cu")
		(net "I3C_SPD_DDREFGH_CPU1_BMC_SDA")
	)
	(segment
		(start 89.938098 -43.848528)
		(end 88.616536 -44.731432)
		(width 0.127)
		(layer "In4.Cu")
		(net "I3C_SPD_DDREFGH_CPU1_BMC_SDA")
	)
	(segment
		(start 74.262488 -95.446596)
		(end 74.262488 -129.390648)
		(width 0.127)
		(layer "In4.Cu")
		(net "I3C_SPD_DDREFGH_CPU1_BMC_SDA")
	)
	(segment
		(start 116.841524 -35.792664)
		(end 106.978704 -35.792664)
		(width 0.127)
		(layer "In4.Cu")
		(net "I3C_SPD_DDREFGH_CPU1_BMC_SDA")
	)
	(segment
		(start 159.23768 -14.318488)
		(end 159.004 -14.552168)
		(width 0.127)
		(layer "In4.Cu")
		(net "I3C_SPD_DDREFGH_CPU1_BMC_SDA")
	)
	(segment
		(start 182.867046 -14.950948)
		(end 181.345586 -13.429488)
		(width 0.127)
		(layer "In4.Cu")
		(net "I3C_SPD_DDREFGH_CPU1_BMC_SDA")
	)
	(segment
		(start 153.326592 -15.458948)
		(end 146.595592 -22.189948)
		(width 0.127)
		(layer "In4.Cu")
		(net "I3C_SPD_DDREFGH_CPU1_BMC_SDA")
	)
	(segment
		(start 81.17078 -51.524408)
		(end 72.02932 -60.665868)
		(width 0.127)
		(layer "In4.Cu")
		(net "I3C_SPD_DDREFGH_CPU1_BMC_SDA")
	)
	(segment
		(start 135.05434 -22.189948)
		(end 129.102104 -22.189948)
		(width 0.127)
		(layer "In4.Cu")
		(net "I3C_SPD_DDREFGH_CPU1_BMC_SDA")
	)
	(segment
		(start 58.92292 -60.665868)
		(end 56.54548 -63.043308)
		(width 0.127)
		(layer "In4.Cu")
		(net "I3C_SPD_DDREFGH_CPU1_BMC_SDA")
	)
	(segment
		(start 56.54548 -77.729588)
		(end 74.262488 -95.446596)
		(width 0.127)
		(layer "In4.Cu")
		(net "I3C_SPD_DDREFGH_CPU1_BMC_SDA")
	)
	(segment
		(start 159.004 -14.552168)
		(end 159.004 -15.077948)
		(width 0.127)
		(layer "In4.Cu")
		(net "I3C_SPD_DDREFGH_CPU1_BMC_SDA")
	)
	(segment
		(start 160.740344 -13.429488)
		(end 159.851344 -14.318488)
		(width 0.127)
		(layer "In4.Cu")
		(net "I3C_SPD_DDREFGH_CPU1_BMC_SDA")
	)
	(segment
		(start 99.222306 -42.890948)
		(end 92.249752 -42.890948)
		(width 0.127)
		(layer "In4.Cu")
		(net "I3C_SPD_DDREFGH_CPU1_BMC_SDA")
	)
	(segment
		(start 129.102104 -22.189948)
		(end 127.12954 -24.162512)
		(width 0.127)
		(layer "In4.Cu")
		(net "I3C_SPD_DDREFGH_CPU1_BMC_SDA")
	)
	(segment
		(start 92.249752 -42.890948)
		(end 89.938098 -43.848528)
		(width 0.127)
		(layer "In4.Cu")
		(net "I3C_SPD_DDREFGH_CPU1_BMC_SDA")
	)
	(segment
		(start 143.14678 -22.189948)
		(end 141.470888 -23.86584)
		(width 0.127)
		(layer "In4.Cu")
		(net "I3C_SPD_DDREFGH_CPU1_BMC_SDA")
	)
	(segment
		(start 159.851344 -14.318488)
		(end 159.23768 -14.318488)
		(width 0.127)
		(layer "In4.Cu")
		(net "I3C_SPD_DDREFGH_CPU1_BMC_SDA")
	)
	(segment
		(start 80.572864 -147.995132)
		(end 81.15808 -147.995132)
		(width 0.127)
		(layer "In4.Cu")
		(net "I3C_SPD_DDREFGH_CPU1_BMC_SDA")
	)
	(segment
		(start 56.54548 -63.043308)
		(end 56.54548 -77.729588)
		(width 0.127)
		(layer "In4.Cu")
		(net "I3C_SPD_DDREFGH_CPU1_BMC_SDA")
	)
	(segment
		(start 72.02932 -60.665868)
		(end 58.92292 -60.665868)
		(width 0.127)
		(layer "In4.Cu")
		(net "I3C_SPD_DDREFGH_CPU1_BMC_SDA")
	)
	(segment
		(start 106.978704 -35.792664)
		(end 100.345748 -42.42562)
		(width 0.127)
		(layer "In4.Cu")
		(net "I3C_SPD_DDREFGH_CPU1_BMC_SDA")
	)
	(segment
		(start 100.345748 -42.42562)
		(end 99.222306 -42.890948)
		(width 0.127)
		(layer "In4.Cu")
		(net "I3C_SPD_DDREFGH_CPU1_BMC_SDA")
	)
	(segment
		(start 136.730232 -23.86584)
		(end 135.05434 -22.189948)
		(width 0.127)
		(layer "In4.Cu")
		(net "I3C_SPD_DDREFGH_CPU1_BMC_SDA")
	)
	(segment
		(start 74.262488 -129.390648)
		(end 79.72552 -134.85368)
		(width 0.127)
		(layer "In4.Cu")
		(net "I3C_SPD_DDREFGH_CPU1_BMC_SDA")
	)
	(segment
		(start 159.004 -15.077948)
		(end 158.623 -15.458948)
		(width 0.127)
		(layer "In4.Cu")
		(net "I3C_SPD_DDREFGH_CPU1_BMC_SDA")
	)
	(segment
		(start 81.82356 -51.524408)
		(end 81.17078 -51.524408)
		(width 0.127)
		(layer "In4.Cu")
		(net "I3C_SPD_DDREFGH_CPU1_BMC_SDA")
	)
	(segment
		(start 81.456784 -146.090132)
		(end 82.384138 -146.090132)
		(width 0.12954)
		(layer "F.Cu")
		(net "I3C_SPD_DDREFGH_CPU1_BMC_SCL")
	)
	(segment
		(start 80.73644 -145.369788)
		(end 81.456784 -146.090132)
		(width 0.12954)
		(layer "F.Cu")
		(net "I3C_SPD_DDREFGH_CPU1_BMC_SCL")
	)
	(via
		(at 80.73644 -145.369788)
		(size 0.508)
		(drill 0.254)
		(layers "F.Cu" "B.Cu")
		(net "I3C_SPD_DDREFGH_CPU1_BMC_SCL")
	)
	(via
		(at 184.059576 -14.823948)
		(size 0.508)
		(drill 0.254)
		(layers "F.Cu" "B.Cu")
		(net "I3C_SPD_DDREFGH_CPU1_BMC_SCL")
	)
	(segment
		(start 184.059576 -14.00048)
		(end 184.059576 -14.823948)
		(width 0.12954)
		(layer "B.Cu")
		(net "I3C_SPD_DDREFGH_CPU1_BMC_SCL")
	)
	(segment
		(start 92.412312 -43.53306)
		(end 90.194384 -44.451778)
		(width 0.127)
		(layer "In4.Cu")
		(net "I3C_SPD_DDREFGH_CPU1_BMC_SCL")
	)
	(segment
		(start 184.059576 -14.950948)
		(end 183.584596 -15.425928)
		(width 0.127)
		(layer "In4.Cu")
		(net "I3C_SPD_DDREFGH_CPU1_BMC_SCL")
	)
	(segment
		(start 125.98146 -27.658568)
		(end 117.136164 -36.503864)
		(width 0.127)
		(layer "In4.Cu")
		(net "I3C_SPD_DDREFGH_CPU1_BMC_SCL")
	)
	(segment
		(start 180.99278 -14.067028)
		(end 161.000948 -14.067028)
		(width 0.127)
		(layer "In4.Cu")
		(net "I3C_SPD_DDREFGH_CPU1_BMC_SCL")
	)
	(segment
		(start 183.584596 -15.425928)
		(end 182.35168 -15.425928)
		(width 0.127)
		(layer "In4.Cu")
		(net "I3C_SPD_DDREFGH_CPU1_BMC_SCL")
	)
	(segment
		(start 129.46888 -22.875748)
		(end 129.06502 -23.279608)
		(width 0.127)
		(layer "In4.Cu")
		(net "I3C_SPD_DDREFGH_CPU1_BMC_SCL")
	)
	(segment
		(start 107.273344 -36.503864)
		(end 100.794058 -42.98315)
		(width 0.127)
		(layer "In4.Cu")
		(net "I3C_SPD_DDREFGH_CPU1_BMC_SCL")
	)
	(segment
		(start 129.06502 -26.596848)
		(end 128.0033 -27.658568)
		(width 0.127)
		(layer "In4.Cu")
		(net "I3C_SPD_DDREFGH_CPU1_BMC_SCL")
	)
	(segment
		(start 182.35168 -15.425928)
		(end 180.99278 -14.067028)
		(width 0.127)
		(layer "In4.Cu")
		(net "I3C_SPD_DDREFGH_CPU1_BMC_SCL")
	)
	(segment
		(start 160.467802 -14.909546)
		(end 159.2834 -16.093948)
		(width 0.127)
		(layer "In4.Cu")
		(net "I3C_SPD_DDREFGH_CPU1_BMC_SCL")
	)
	(segment
		(start 117.136164 -36.503864)
		(end 107.273344 -36.503864)
		(width 0.127)
		(layer "In4.Cu")
		(net "I3C_SPD_DDREFGH_CPU1_BMC_SCL")
	)
	(segment
		(start 57.25668 -77.434948)
		(end 74.973688 -95.151956)
		(width 0.127)
		(layer "In4.Cu")
		(net "I3C_SPD_DDREFGH_CPU1_BMC_SCL")
	)
	(segment
		(start 146.826224 -22.875748)
		(end 143.79194 -22.875748)
		(width 0.127)
		(layer "In4.Cu")
		(net "I3C_SPD_DDREFGH_CPU1_BMC_SCL")
	)
	(segment
		(start 142.141448 -24.52624)
		(end 136.453372 -24.52624)
		(width 0.127)
		(layer "In4.Cu")
		(net "I3C_SPD_DDREFGH_CPU1_BMC_SCL")
	)
	(segment
		(start 136.453372 -24.52624)
		(end 134.80288 -22.875748)
		(width 0.127)
		(layer "In4.Cu")
		(net "I3C_SPD_DDREFGH_CPU1_BMC_SCL")
	)
	(segment
		(start 90.194384 -44.451778)
		(end 89.313766 -45.040042)
		(width 0.127)
		(layer "In4.Cu")
		(net "I3C_SPD_DDREFGH_CPU1_BMC_SCL")
	)
	(segment
		(start 161.000948 -14.067028)
		(end 160.467802 -14.600174)
		(width 0.127)
		(layer "In4.Cu")
		(net "I3C_SPD_DDREFGH_CPU1_BMC_SCL")
	)
	(segment
		(start 134.80288 -22.875748)
		(end 129.46888 -22.875748)
		(width 0.127)
		(layer "In4.Cu")
		(net "I3C_SPD_DDREFGH_CPU1_BMC_SCL")
	)
	(segment
		(start 184.059576 -14.823948)
		(end 184.059576 -14.950948)
		(width 0.127)
		(layer "In4.Cu")
		(net "I3C_SPD_DDREFGH_CPU1_BMC_SCL")
	)
	(segment
		(start 72.32396 -61.377068)
		(end 59.21756 -61.377068)
		(width 0.127)
		(layer "In4.Cu")
		(net "I3C_SPD_DDREFGH_CPU1_BMC_SCL")
	)
	(segment
		(start 81.15808 -144.948148)
		(end 80.73644 -145.369788)
		(width 0.127)
		(layer "In4.Cu")
		(net "I3C_SPD_DDREFGH_CPU1_BMC_SCL")
	)
	(segment
		(start 128.0033 -27.658568)
		(end 125.98146 -27.658568)
		(width 0.127)
		(layer "In4.Cu")
		(net "I3C_SPD_DDREFGH_CPU1_BMC_SCL")
	)
	(segment
		(start 81.46542 -52.235608)
		(end 72.32396 -61.377068)
		(width 0.127)
		(layer "In4.Cu")
		(net "I3C_SPD_DDREFGH_CPU1_BMC_SCL")
	)
	(segment
		(start 59.21756 -61.377068)
		(end 57.25668 -63.337948)
		(width 0.127)
		(layer "In4.Cu")
		(net "I3C_SPD_DDREFGH_CPU1_BMC_SCL")
	)
	(segment
		(start 129.06502 -23.279608)
		(end 129.06502 -26.596848)
		(width 0.127)
		(layer "In4.Cu")
		(net "I3C_SPD_DDREFGH_CPU1_BMC_SCL")
	)
	(segment
		(start 100.794058 -42.98315)
		(end 99.4664 -43.53306)
		(width 0.127)
		(layer "In4.Cu")
		(net "I3C_SPD_DDREFGH_CPU1_BMC_SCL")
	)
	(segment
		(start 82.1182 -52.235608)
		(end 81.46542 -52.235608)
		(width 0.127)
		(layer "In4.Cu")
		(net "I3C_SPD_DDREFGH_CPU1_BMC_SCL")
	)
	(segment
		(start 89.313766 -45.040042)
		(end 82.1182 -52.235608)
		(width 0.127)
		(layer "In4.Cu")
		(net "I3C_SPD_DDREFGH_CPU1_BMC_SCL")
	)
	(segment
		(start 143.79194 -22.875748)
		(end 142.141448 -24.52624)
		(width 0.127)
		(layer "In4.Cu")
		(net "I3C_SPD_DDREFGH_CPU1_BMC_SCL")
	)
	(segment
		(start 74.973688 -129.074164)
		(end 81.15808 -135.258556)
		(width 0.127)
		(layer "In4.Cu")
		(net "I3C_SPD_DDREFGH_CPU1_BMC_SCL")
	)
	(segment
		(start 159.2834 -16.093948)
		(end 153.608024 -16.093948)
		(width 0.127)
		(layer "In4.Cu")
		(net "I3C_SPD_DDREFGH_CPU1_BMC_SCL")
	)
	(segment
		(start 160.467802 -14.600174)
		(end 160.467802 -14.909546)
		(width 0.127)
		(layer "In4.Cu")
		(net "I3C_SPD_DDREFGH_CPU1_BMC_SCL")
	)
	(segment
		(start 74.973688 -95.151956)
		(end 74.973688 -129.074164)
		(width 0.127)
		(layer "In4.Cu")
		(net "I3C_SPD_DDREFGH_CPU1_BMC_SCL")
	)
	(segment
		(start 81.15808 -135.258556)
		(end 81.15808 -144.948148)
		(width 0.127)
		(layer "In4.Cu")
		(net "I3C_SPD_DDREFGH_CPU1_BMC_SCL")
	)
	(segment
		(start 153.608024 -16.093948)
		(end 146.826224 -22.875748)
		(width 0.127)
		(layer "In4.Cu")
		(net "I3C_SPD_DDREFGH_CPU1_BMC_SCL")
	)
	(segment
		(start 57.25668 -63.337948)
		(end 57.25668 -77.434948)
		(width 0.127)
		(layer "In4.Cu")
		(net "I3C_SPD_DDREFGH_CPU1_BMC_SCL")
	)
	(segment
		(start 99.4664 -43.53306)
		(end 92.412312 -43.53306)
		(width 0.127)
		(layer "In4.Cu")
		(net "I3C_SPD_DDREFGH_CPU1_BMC_SCL")
	)
	(segment
		(start 184.461912 -12.683998)
		(end 184.461658 -12.683744)
		(width 0.12954)
		(layer "F.Cu")
		(net "I3C_SPD_DDREFGH_CPU1_BMC_R_SDA")
	)
	(segment
		(start 183.57596 -11.648948)
		(end 182.83428 -11.648948)
		(width 0.12954)
		(layer "F.Cu")
		(net "I3C_SPD_DDREFGH_CPU1_BMC_R_SDA")
	)
	(segment
		(start 184.461658 -12.683744)
		(end 184.461658 -12.534646)
		(width 0.12954)
		(layer "F.Cu")
		(net "I3C_SPD_DDREFGH_CPU1_BMC_R_SDA")
	)
	(segment
		(start 184.461658 -12.534646)
		(end 183.57596 -11.648948)
		(width 0.12954)
		(layer "F.Cu")
		(net "I3C_SPD_DDREFGH_CPU1_BMC_R_SDA")
	)
	(segment
		(start 184.461912 -13.600176)
		(end 184.461912 -12.683998)
		(width 0.12954)
		(layer "F.Cu")
		(net "I3C_SPD_DDREFGH_CPU1_BMC_R_SDA")
	)
	(via
		(at 182.83428 -11.648948)
		(size 0.508)
		(drill 0.254)
		(layers "F.Cu" "B.Cu")
		(net "I3C_SPD_DDREFGH_CPU1_BMC_R_SDA")
	)
	(segment
		(start 182.83428 -11.648948)
		(end 182.867046 -11.681714)
		(width 0.12954)
		(layer "B.Cu")
		(net "I3C_SPD_DDREFGH_CPU1_BMC_R_SDA")
	)
	(segment
		(start 182.867046 -11.681714)
		(end 182.867046 -13.20038)
		(width 0.12954)
		(layer "B.Cu")
		(net "I3C_SPD_DDREFGH_CPU1_BMC_R_SDA")
	)
	(segment
		(start 185.06186 -12.057888)
		(end 184.05348 -11.049508)
		(width 0.12954)
		(layer "F.Cu")
		(net "I3C_SPD_DDREFGH_CPU1_BMC_R_SCL")
	)
	(segment
		(start 185.062114 -12.683998)
		(end 185.06186 -12.683744)
		(width 0.12954)
		(layer "F.Cu")
		(net "I3C_SPD_DDREFGH_CPU1_BMC_R_SCL")
	)
	(segment
		(start 185.06186 -12.683744)
		(end 185.06186 -12.057888)
		(width 0.12954)
		(layer "F.Cu")
		(net "I3C_SPD_DDREFGH_CPU1_BMC_R_SCL")
	)
	(segment
		(start 184.05348 -11.049508)
		(end 184.05348 -10.175748)
		(width 0.12954)
		(layer "F.Cu")
		(net "I3C_SPD_DDREFGH_CPU1_BMC_R_SCL")
	)
	(segment
		(start 185.062114 -13.600176)
		(end 185.062114 -12.683998)
		(width 0.12954)
		(layer "F.Cu")
		(net "I3C_SPD_DDREFGH_CPU1_BMC_R_SCL")
	)
	(via
		(at 184.05348 -10.175748)
		(size 0.508)
		(drill 0.254)
		(layers "F.Cu" "B.Cu")
		(net "I3C_SPD_DDREFGH_CPU1_BMC_R_SCL")
	)
	(segment
		(start 184.05348 -10.175748)
		(end 184.059576 -10.181844)
		(width 0.12954)
		(layer "B.Cu")
		(net "I3C_SPD_DDREFGH_CPU1_BMC_R_SCL")
	)
	(segment
		(start 184.059576 -10.181844)
		(end 184.059576 -13.20038)
		(width 0.12954)
		(layer "B.Cu")
		(net "I3C_SPD_DDREFGH_CPU1_BMC_R_SCL")
	)
	(segment
		(start 368.038634 -228.180646)
		(end 368.038634 -227.64496)
		(width 0.12954)
		(layer "F.Cu")
		(net "I3C_SPD_DDREFGH_CPU0_SDA")
	)
	(segment
		(start 368.03838 -228.1809)
		(end 368.038634 -228.180646)
		(width 0.12954)
		(layer "F.Cu")
		(net "I3C_SPD_DDREFGH_CPU0_SDA")
	)
	(via
		(at 368.038634 -227.64496)
		(size 0.4572)
		(drill 0.2032)
		(layers "F.Cu" "B.Cu")
		(net "I3C_SPD_DDREFGH_CPU0_SDA")
	)
	(via
		(at 380.190502 -192.455546)
		(size 0.6604)
		(drill 0.3302)
		(layers "F.Cu" "B.Cu")
		(net "I3C_SPD_DDREFGH_CPU0_SDA")
	)
	(segment
		(start 372.939564 -227.329238)
		(end 372.924832 -227.320602)
		(width 0.0889)
		(layer "B.Cu")
		(net "I3C_SPD_DDREFGH_CPU0_SDA")
	)
	(segment
		(start 382.337564 -227.329238)
		(end 382.322832 -227.320602)
		(width 0.0889)
		(layer "B.Cu")
		(net "I3C_SPD_DDREFGH_CPU0_SDA")
	)
	(segment
		(start 379.078998 -191.83985)
		(end 379.574806 -191.83985)
		(width 0.12954)
		(layer "B.Cu")
		(net "I3C_SPD_DDREFGH_CPU0_SDA")
	)
	(segment
		(start 373.879364 -227.329238)
		(end 373.864632 -227.320602)
		(width 0.0889)
		(layer "B.Cu")
		(net "I3C_SPD_DDREFGH_CPU0_SDA")
	)
	(segment
		(start 388.209028 -226.19208)
		(end 386.83184 -227.569268)
		(width 0.12954)
		(layer "B.Cu")
		(net "I3C_SPD_DDREFGH_CPU0_SDA")
	)
	(segment
		(start 369.730782 -227.320602)
		(end 369.720368 -227.326698)
		(width 0.0889)
		(layer "B.Cu")
		(net "I3C_SPD_DDREFGH_CPU0_SDA")
	)
	(segment
		(start 377.638564 -227.329238)
		(end 377.623832 -227.320602)
		(width 0.0889)
		(layer "B.Cu")
		(net "I3C_SPD_DDREFGH_CPU0_SDA")
	)
	(segment
		(start 385.191762 -227.48748)
		(end 384.974338 -227.270056)
		(width 0.0889)
		(layer "B.Cu")
		(net "I3C_SPD_DDREFGH_CPU0_SDA")
	)
	(segment
		(start 371.059964 -227.329238)
		(end 371.045232 -227.320602)
		(width 0.0889)
		(layer "B.Cu")
		(net "I3C_SPD_DDREFGH_CPU0_SDA")
	)
	(segment
		(start 386.83184 -227.569268)
		(end 385.27355 -227.569268)
		(width 0.12954)
		(layer "B.Cu")
		(net "I3C_SPD_DDREFGH_CPU0_SDA")
	)
	(segment
		(start 380.457964 -227.329238)
		(end 380.443232 -227.320602)
		(width 0.0889)
		(layer "B.Cu")
		(net "I3C_SPD_DDREFGH_CPU0_SDA")
	)
	(segment
		(start 379.518164 -227.329238)
		(end 379.503432 -227.320602)
		(width 0.0889)
		(layer "B.Cu")
		(net "I3C_SPD_DDREFGH_CPU0_SDA")
	)
	(segment
		(start 370.115592 -227.326698)
		(end 370.105178 -227.320602)
		(width 0.0889)
		(layer "B.Cu")
		(net "I3C_SPD_DDREFGH_CPU0_SDA")
	)
	(segment
		(start 385.51231 -196.57441)
		(end 390.018524 -201.080624)
		(width 0.12954)
		(layer "B.Cu")
		(net "I3C_SPD_DDREFGH_CPU0_SDA")
	)
	(segment
		(start 378.712476 -191.195198)
		(end 379.720602 -191.195198)
		(width 0.12954)
		(layer "B.Cu")
		(net "I3C_SPD_DDREFGH_CPU0_SDA")
	)
	(segment
		(start 378.711968 -191.195706)
		(end 378.712476 -191.195198)
		(width 0.12954)
		(layer "B.Cu")
		(net "I3C_SPD_DDREFGH_CPU0_SDA")
	)
	(segment
		(start 388.209028 -225.414332)
		(end 388.209028 -226.19208)
		(width 0.12954)
		(layer "B.Cu")
		(net "I3C_SPD_DDREFGH_CPU0_SDA")
	)
	(segment
		(start 379.574806 -191.83985)
		(end 380.190502 -192.455546)
		(width 0.12954)
		(layer "B.Cu")
		(net "I3C_SPD_DDREFGH_CPU0_SDA")
	)
	(segment
		(start 378.711968 -191.195706)
		(end 378.711968 -191.47282)
		(width 0.12954)
		(layer "B.Cu")
		(net "I3C_SPD_DDREFGH_CPU0_SDA")
	)
	(segment
		(start 384.974338 -227.270056)
		(end 384.955034 -227.270056)
		(width 0.0889)
		(layer "B.Cu")
		(net "I3C_SPD_DDREFGH_CPU0_SDA")
	)
	(segment
		(start 378.711968 -191.47282)
		(end 379.078998 -191.83985)
		(width 0.12954)
		(layer "B.Cu")
		(net "I3C_SPD_DDREFGH_CPU0_SDA")
	)
	(segment
		(start 376.309382 -227.320602)
		(end 376.29465 -227.329238)
		(width 0.0889)
		(layer "B.Cu")
		(net "I3C_SPD_DDREFGH_CPU0_SDA")
	)
	(segment
		(start 376.694192 -227.326698)
		(end 376.683778 -227.320602)
		(width 0.0889)
		(layer "B.Cu")
		(net "I3C_SPD_DDREFGH_CPU0_SDA")
	)
	(segment
		(start 368.195098 -227.373942)
		(end 368.038634 -227.64496)
		(width 0.0889)
		(layer "B.Cu")
		(net "I3C_SPD_DDREFGH_CPU0_SDA")
	)
	(segment
		(start 375.369582 -227.320602)
		(end 375.359168 -227.326698)
		(width 0.0889)
		(layer "B.Cu")
		(net "I3C_SPD_DDREFGH_CPU0_SDA")
	)
	(segment
		(start 384.309366 -196.57441)
		(end 385.51231 -196.57441)
		(width 0.12954)
		(layer "B.Cu")
		(net "I3C_SPD_DDREFGH_CPU0_SDA")
	)
	(segment
		(start 390.018524 -223.604836)
		(end 388.209028 -225.414332)
		(width 0.12954)
		(layer "B.Cu")
		(net "I3C_SPD_DDREFGH_CPU0_SDA")
	)
	(segment
		(start 390.018524 -201.080624)
		(end 390.018524 -223.604836)
		(width 0.12954)
		(layer "B.Cu")
		(net "I3C_SPD_DDREFGH_CPU0_SDA")
	)
	(segment
		(start 368.283998 -227.35032)
		(end 368.195098 -227.373942)
		(width 0.0889)
		(layer "B.Cu")
		(net "I3C_SPD_DDREFGH_CPU0_SDA")
	)
	(segment
		(start 385.27355 -227.569268)
		(end 385.191762 -227.48748)
		(width 0.12954)
		(layer "B.Cu")
		(net "I3C_SPD_DDREFGH_CPU0_SDA")
	)
	(segment
		(start 380.190502 -192.455546)
		(end 384.309366 -196.57441)
		(width 0.12954)
		(layer "B.Cu")
		(net "I3C_SPD_DDREFGH_CPU0_SDA")
	)
	(arc
		(start 372.550436 -227.320602)
		(mid 372.267734 -227.396378)
		(end 371.985032 -227.320602)
		(width 0.0889)
		(layer "B.Cu")
		(net "I3C_SPD_DDREFGH_CPU0_SDA")
	)
	(arc
		(start 376.29465 -227.329238)
		(mid 376.018175 -227.396558)
		(end 375.743978 -227.320602)
		(width 0.0889)
		(layer "B.Cu")
		(net "I3C_SPD_DDREFGH_CPU0_SDA")
	)
	(arc
		(start 372.924832 -227.320602)
		(mid 372.737634 -227.270459)
		(end 372.550436 -227.320602)
		(width 0.0889)
		(layer "B.Cu")
		(net "I3C_SPD_DDREFGH_CPU0_SDA")
	)
	(arc
		(start 373.864632 -227.320602)
		(mid 373.677434 -227.270459)
		(end 373.490236 -227.320602)
		(width 0.0889)
		(layer "B.Cu")
		(net "I3C_SPD_DDREFGH_CPU0_SDA")
	)
	(arc
		(start 368.791236 -227.320602)
		(mid 368.541139 -227.395662)
		(end 368.283998 -227.35032)
		(width 0.0889)
		(layer "B.Cu")
		(net "I3C_SPD_DDREFGH_CPU0_SDA")
	)
	(arc
		(start 379.129036 -227.320602)
		(mid 378.846334 -227.396378)
		(end 378.563632 -227.320602)
		(width 0.0889)
		(layer "B.Cu")
		(net "I3C_SPD_DDREFGH_CPU0_SDA")
	)
	(arc
		(start 378.189236 -227.320602)
		(mid 377.915037 -227.396437)
		(end 377.638564 -227.329238)
		(width 0.0889)
		(layer "B.Cu")
		(net "I3C_SPD_DDREFGH_CPU0_SDA")
	)
	(arc
		(start 371.610636 -227.320602)
		(mid 371.336437 -227.396437)
		(end 371.059964 -227.329238)
		(width 0.0889)
		(layer "B.Cu")
		(net "I3C_SPD_DDREFGH_CPU0_SDA")
	)
	(arc
		(start 371.985032 -227.320602)
		(mid 371.797834 -227.270459)
		(end 371.610636 -227.320602)
		(width 0.0889)
		(layer "B.Cu")
		(net "I3C_SPD_DDREFGH_CPU0_SDA")
	)
	(arc
		(start 375.743978 -227.320602)
		(mid 375.55678 -227.270459)
		(end 375.369582 -227.320602)
		(width 0.0889)
		(layer "B.Cu")
		(net "I3C_SPD_DDREFGH_CPU0_SDA")
	)
	(arc
		(start 383.262632 -227.320602)
		(mid 383.075434 -227.270459)
		(end 382.888236 -227.320602)
		(width 0.0889)
		(layer "B.Cu")
		(net "I3C_SPD_DDREFGH_CPU0_SDA")
	)
	(arc
		(start 384.202432 -227.320602)
		(mid 384.015234 -227.270459)
		(end 383.828036 -227.320602)
		(width 0.0889)
		(layer "B.Cu")
		(net "I3C_SPD_DDREFGH_CPU0_SDA")
	)
	(arc
		(start 371.045232 -227.320602)
		(mid 370.858034 -227.270459)
		(end 370.670836 -227.320602)
		(width 0.0889)
		(layer "B.Cu")
		(net "I3C_SPD_DDREFGH_CPU0_SDA")
	)
	(arc
		(start 377.249436 -227.320602)
		(mid 376.972623 -227.396472)
		(end 376.694192 -227.326698)
		(width 0.0889)
		(layer "B.Cu")
		(net "I3C_SPD_DDREFGH_CPU0_SDA")
	)
	(arc
		(start 384.955034 -227.270056)
		(mid 384.858106 -227.283007)
		(end 384.767836 -227.320602)
		(width 0.0889)
		(layer "B.Cu")
		(net "I3C_SPD_DDREFGH_CPU0_SDA")
	)
	(arc
		(start 381.008636 -227.320602)
		(mid 380.734437 -227.396437)
		(end 380.457964 -227.329238)
		(width 0.0889)
		(layer "B.Cu")
		(net "I3C_SPD_DDREFGH_CPU0_SDA")
	)
	(arc
		(start 370.105178 -227.320602)
		(mid 369.91798 -227.270459)
		(end 369.730782 -227.320602)
		(width 0.0889)
		(layer "B.Cu")
		(net "I3C_SPD_DDREFGH_CPU0_SDA")
	)
	(arc
		(start 373.490236 -227.320602)
		(mid 373.216037 -227.396437)
		(end 372.939564 -227.329238)
		(width 0.0889)
		(layer "B.Cu")
		(net "I3C_SPD_DDREFGH_CPU0_SDA")
	)
	(arc
		(start 379.503432 -227.320602)
		(mid 379.316234 -227.270459)
		(end 379.129036 -227.320602)
		(width 0.0889)
		(layer "B.Cu")
		(net "I3C_SPD_DDREFGH_CPU0_SDA")
	)
	(arc
		(start 380.068836 -227.320602)
		(mid 379.794637 -227.396437)
		(end 379.518164 -227.329238)
		(width 0.0889)
		(layer "B.Cu")
		(net "I3C_SPD_DDREFGH_CPU0_SDA")
	)
	(arc
		(start 384.767836 -227.320602)
		(mid 384.485134 -227.396378)
		(end 384.202432 -227.320602)
		(width 0.0889)
		(layer "B.Cu")
		(net "I3C_SPD_DDREFGH_CPU0_SDA")
	)
	(arc
		(start 369.720368 -227.326698)
		(mid 369.44219 -227.396421)
		(end 369.165632 -227.320602)
		(width 0.0889)
		(layer "B.Cu")
		(net "I3C_SPD_DDREFGH_CPU0_SDA")
	)
	(arc
		(start 375.359168 -227.326698)
		(mid 375.08099 -227.396421)
		(end 374.804432 -227.320602)
		(width 0.0889)
		(layer "B.Cu")
		(net "I3C_SPD_DDREFGH_CPU0_SDA")
	)
	(arc
		(start 381.383032 -227.320602)
		(mid 381.195834 -227.270459)
		(end 381.008636 -227.320602)
		(width 0.0889)
		(layer "B.Cu")
		(net "I3C_SPD_DDREFGH_CPU0_SDA")
	)
	(arc
		(start 369.165632 -227.320602)
		(mid 368.978434 -227.270459)
		(end 368.791236 -227.320602)
		(width 0.0889)
		(layer "B.Cu")
		(net "I3C_SPD_DDREFGH_CPU0_SDA")
	)
	(arc
		(start 378.563632 -227.320602)
		(mid 378.376434 -227.270459)
		(end 378.189236 -227.320602)
		(width 0.0889)
		(layer "B.Cu")
		(net "I3C_SPD_DDREFGH_CPU0_SDA")
	)
	(arc
		(start 383.828036 -227.320602)
		(mid 383.545334 -227.396378)
		(end 383.262632 -227.320602)
		(width 0.0889)
		(layer "B.Cu")
		(net "I3C_SPD_DDREFGH_CPU0_SDA")
	)
	(arc
		(start 374.430036 -227.320602)
		(mid 374.155837 -227.396437)
		(end 373.879364 -227.329238)
		(width 0.0889)
		(layer "B.Cu")
		(net "I3C_SPD_DDREFGH_CPU0_SDA")
	)
	(arc
		(start 382.322832 -227.320602)
		(mid 382.135634 -227.270459)
		(end 381.948436 -227.320602)
		(width 0.0889)
		(layer "B.Cu")
		(net "I3C_SPD_DDREFGH_CPU0_SDA")
	)
	(arc
		(start 380.443232 -227.320602)
		(mid 380.256034 -227.270459)
		(end 380.068836 -227.320602)
		(width 0.0889)
		(layer "B.Cu")
		(net "I3C_SPD_DDREFGH_CPU0_SDA")
	)
	(arc
		(start 374.804432 -227.320602)
		(mid 374.617234 -227.270459)
		(end 374.430036 -227.320602)
		(width 0.0889)
		(layer "B.Cu")
		(net "I3C_SPD_DDREFGH_CPU0_SDA")
	)
	(arc
		(start 376.683778 -227.320602)
		(mid 376.49658 -227.270459)
		(end 376.309382 -227.320602)
		(width 0.0889)
		(layer "B.Cu")
		(net "I3C_SPD_DDREFGH_CPU0_SDA")
	)
	(arc
		(start 382.888236 -227.320602)
		(mid 382.614037 -227.396437)
		(end 382.337564 -227.329238)
		(width 0.0889)
		(layer "B.Cu")
		(net "I3C_SPD_DDREFGH_CPU0_SDA")
	)
	(arc
		(start 377.623832 -227.320602)
		(mid 377.436634 -227.270459)
		(end 377.249436 -227.320602)
		(width 0.0889)
		(layer "B.Cu")
		(net "I3C_SPD_DDREFGH_CPU0_SDA")
	)
	(arc
		(start 381.948436 -227.320602)
		(mid 381.665734 -227.396378)
		(end 381.383032 -227.320602)
		(width 0.0889)
		(layer "B.Cu")
		(net "I3C_SPD_DDREFGH_CPU0_SDA")
	)
	(arc
		(start 370.670836 -227.320602)
		(mid 370.394023 -227.396472)
		(end 370.115592 -227.326698)
		(width 0.0889)
		(layer "B.Cu")
		(net "I3C_SPD_DDREFGH_CPU0_SDA")
	)
	(segment
		(start 368.50828 -227.36683)
		(end 368.50828 -226.831144)
		(width 0.12954)
		(layer "F.Cu")
		(net "I3C_SPD_DDREFGH_CPU0_SCL")
	)
	(segment
		(start 368.508534 -227.367084)
		(end 368.50828 -227.36683)
		(width 0.12954)
		(layer "F.Cu")
		(net "I3C_SPD_DDREFGH_CPU0_SCL")
	)
	(via
		(at 368.50828 -226.831144)
		(size 0.4572)
		(drill 0.2032)
		(layers "F.Cu" "B.Cu")
		(net "I3C_SPD_DDREFGH_CPU0_SCL")
	)
	(via
		(at 378.304298 -192.51295)
		(size 0.6604)
		(drill 0.3302)
		(layers "F.Cu" "B.Cu")
		(net "I3C_SPD_DDREFGH_CPU0_SCL")
	)
	(segment
		(start 378.304298 -192.51295)
		(end 379.310138 -192.51295)
		(width 0.12954)
		(layer "B.Cu")
		(net "I3C_SPD_DDREFGH_CPU0_SCL")
	)
	(segment
		(start 379.598682 -227.155502)
		(end 379.588268 -227.149406)
		(width 0.0889)
		(layer "B.Cu")
		(net "I3C_SPD_DDREFGH_CPU0_SCL")
	)
	(segment
		(start 368.372898 -227.18014)
		(end 368.351816 -227.102162)
		(width 0.0889)
		(layer "B.Cu")
		(net "I3C_SPD_DDREFGH_CPU0_SCL")
	)
	(segment
		(start 385.810252 -227.079556)
		(end 385.3815 -227.079556)
		(width 0.12954)
		(layer "B.Cu")
		(net "I3C_SPD_DDREFGH_CPU0_SCL")
	)
	(segment
		(start 385.280662 -197.28053)
		(end 389.355584 -201.355452)
		(width 0.12954)
		(layer "B.Cu")
		(net "I3C_SPD_DDREFGH_CPU0_SCL")
	)
	(segment
		(start 384.077718 -197.28053)
		(end 385.280662 -197.28053)
		(width 0.12954)
		(layer "B.Cu")
		(net "I3C_SPD_DDREFGH_CPU0_SCL")
	)
	(segment
		(start 376.224546 -227.149406)
		(end 376.214132 -227.155502)
		(width 0.0889)
		(layer "B.Cu")
		(net "I3C_SPD_DDREFGH_CPU0_SCL")
	)
	(segment
		(start 377.632214 -191.103758)
		(end 377.632214 -191.840866)
		(width 0.12954)
		(layer "B.Cu")
		(net "I3C_SPD_DDREFGH_CPU0_SCL")
	)
	(segment
		(start 385.3815 -227.079556)
		(end 384.95478 -227.079556)
		(width 0.0889)
		(layer "B.Cu")
		(net "I3C_SPD_DDREFGH_CPU0_SCL")
	)
	(segment
		(start 377.632214 -191.840866)
		(end 378.304298 -192.51295)
		(width 0.12954)
		(layer "B.Cu")
		(net "I3C_SPD_DDREFGH_CPU0_SCL")
	)
	(segment
		(start 371.140482 -227.155502)
		(end 371.12575 -227.146866)
		(width 0.0889)
		(layer "B.Cu")
		(net "I3C_SPD_DDREFGH_CPU0_SCL")
	)
	(segment
		(start 373.020082 -227.155502)
		(end 373.009668 -227.149406)
		(width 0.0889)
		(layer "B.Cu")
		(net "I3C_SPD_DDREFGH_CPU0_SCL")
	)
	(segment
		(start 377.719082 -227.155502)
		(end 377.70435 -227.146866)
		(width 0.0889)
		(layer "B.Cu")
		(net "I3C_SPD_DDREFGH_CPU0_SCL")
	)
	(segment
		(start 368.351816 -227.102162)
		(end 368.50828 -226.831144)
		(width 0.0889)
		(layer "B.Cu")
		(net "I3C_SPD_DDREFGH_CPU0_SCL")
	)
	(segment
		(start 374.899936 -227.155502)
		(end 374.889522 -227.149406)
		(width 0.0889)
		(layer "B.Cu")
		(net "I3C_SPD_DDREFGH_CPU0_SCL")
	)
	(segment
		(start 378.659136 -227.155502)
		(end 378.648722 -227.149406)
		(width 0.0889)
		(layer "B.Cu")
		(net "I3C_SPD_DDREFGH_CPU0_SCL")
	)
	(segment
		(start 369.261136 -227.155502)
		(end 369.250722 -227.149406)
		(width 0.0889)
		(layer "B.Cu")
		(net "I3C_SPD_DDREFGH_CPU0_SCL")
	)
	(segment
		(start 373.959882 -227.155502)
		(end 373.94515 -227.146866)
		(width 0.0889)
		(layer "B.Cu")
		(net "I3C_SPD_DDREFGH_CPU0_SCL")
	)
	(segment
		(start 372.080536 -227.155502)
		(end 372.070122 -227.149406)
		(width 0.0889)
		(layer "B.Cu")
		(net "I3C_SPD_DDREFGH_CPU0_SCL")
	)
	(segment
		(start 381.478536 -227.155502)
		(end 381.468122 -227.149406)
		(width 0.0889)
		(layer "B.Cu")
		(net "I3C_SPD_DDREFGH_CPU0_SCL")
	)
	(segment
		(start 389.355584 -223.534224)
		(end 385.810252 -227.079556)
		(width 0.12954)
		(layer "B.Cu")
		(net "I3C_SPD_DDREFGH_CPU0_SCL")
	)
	(segment
		(start 382.418082 -227.155502)
		(end 382.407668 -227.149406)
		(width 0.0889)
		(layer "B.Cu")
		(net "I3C_SPD_DDREFGH_CPU0_SCL")
	)
	(segment
		(start 380.538482 -227.155502)
		(end 380.52375 -227.146866)
		(width 0.0889)
		(layer "B.Cu")
		(net "I3C_SPD_DDREFGH_CPU0_SCL")
	)
	(segment
		(start 389.355584 -201.355452)
		(end 389.355584 -223.534224)
		(width 0.12954)
		(layer "B.Cu")
		(net "I3C_SPD_DDREFGH_CPU0_SCL")
	)
	(segment
		(start 376.618754 -191.103758)
		(end 377.632214 -191.103758)
		(width 0.12954)
		(layer "B.Cu")
		(net "I3C_SPD_DDREFGH_CPU0_SCL")
	)
	(segment
		(start 383.358136 -227.155502)
		(end 383.347722 -227.149406)
		(width 0.0889)
		(layer "B.Cu")
		(net "I3C_SPD_DDREFGH_CPU0_SCL")
	)
	(segment
		(start 369.645946 -227.149406)
		(end 369.635532 -227.155502)
		(width 0.0889)
		(layer "B.Cu")
		(net "I3C_SPD_DDREFGH_CPU0_SCL")
	)
	(segment
		(start 379.310138 -192.51295)
		(end 384.077718 -197.28053)
		(width 0.12954)
		(layer "B.Cu")
		(net "I3C_SPD_DDREFGH_CPU0_SCL")
	)
	(segment
		(start 375.289064 -227.146866)
		(end 375.274332 -227.155502)
		(width 0.0889)
		(layer "B.Cu")
		(net "I3C_SPD_DDREFGH_CPU0_SCL")
	)
	(arc
		(start 384.95478 -227.079556)
		(mid 384.808547 -227.098921)
		(end 384.672332 -227.155502)
		(width 0.0889)
		(layer "B.Cu")
		(net "I3C_SPD_DDREFGH_CPU0_SCL")
	)
	(arc
		(start 373.94515 -227.146866)
		(mid 373.668675 -227.079546)
		(end 373.394478 -227.155502)
		(width 0.0889)
		(layer "B.Cu")
		(net "I3C_SPD_DDREFGH_CPU0_SCL")
	)
	(arc
		(start 375.839736 -227.155502)
		(mid 375.565537 -227.079667)
		(end 375.289064 -227.146866)
		(width 0.0889)
		(layer "B.Cu")
		(net "I3C_SPD_DDREFGH_CPU0_SCL")
	)
	(arc
		(start 374.889522 -227.149406)
		(mid 374.61109 -227.07956)
		(end 374.334278 -227.155502)
		(width 0.0889)
		(layer "B.Cu")
		(net "I3C_SPD_DDREFGH_CPU0_SCL")
	)
	(arc
		(start 368.695478 -227.155502)
		(mid 368.53699 -227.204435)
		(end 368.372898 -227.18014)
		(width 0.0889)
		(layer "B.Cu")
		(net "I3C_SPD_DDREFGH_CPU0_SCL")
	)
	(arc
		(start 376.214132 -227.155502)
		(mid 376.026934 -227.205645)
		(end 375.839736 -227.155502)
		(width 0.0889)
		(layer "B.Cu")
		(net "I3C_SPD_DDREFGH_CPU0_SCL")
	)
	(arc
		(start 383.347722 -227.149406)
		(mid 383.06929 -227.07956)
		(end 382.792478 -227.155502)
		(width 0.0889)
		(layer "B.Cu")
		(net "I3C_SPD_DDREFGH_CPU0_SCL")
	)
	(arc
		(start 375.274332 -227.155502)
		(mid 375.087134 -227.205645)
		(end 374.899936 -227.155502)
		(width 0.0889)
		(layer "B.Cu")
		(net "I3C_SPD_DDREFGH_CPU0_SCL")
	)
	(arc
		(start 384.297936 -227.155502)
		(mid 384.015234 -227.079726)
		(end 383.732532 -227.155502)
		(width 0.0889)
		(layer "B.Cu")
		(net "I3C_SPD_DDREFGH_CPU0_SCL")
	)
	(arc
		(start 382.792478 -227.155502)
		(mid 382.60528 -227.205645)
		(end 382.418082 -227.155502)
		(width 0.0889)
		(layer "B.Cu")
		(net "I3C_SPD_DDREFGH_CPU0_SCL")
	)
	(arc
		(start 369.250722 -227.149406)
		(mid 368.97229 -227.07956)
		(end 368.695478 -227.155502)
		(width 0.0889)
		(layer "B.Cu")
		(net "I3C_SPD_DDREFGH_CPU0_SCL")
	)
	(arc
		(start 380.52375 -227.146866)
		(mid 380.247275 -227.079546)
		(end 379.973078 -227.155502)
		(width 0.0889)
		(layer "B.Cu")
		(net "I3C_SPD_DDREFGH_CPU0_SCL")
	)
	(arc
		(start 381.468122 -227.149406)
		(mid 381.18969 -227.07956)
		(end 380.912878 -227.155502)
		(width 0.0889)
		(layer "B.Cu")
		(net "I3C_SPD_DDREFGH_CPU0_SCL")
	)
	(arc
		(start 380.912878 -227.155502)
		(mid 380.72568 -227.205645)
		(end 380.538482 -227.155502)
		(width 0.0889)
		(layer "B.Cu")
		(net "I3C_SPD_DDREFGH_CPU0_SCL")
	)
	(arc
		(start 372.454932 -227.155502)
		(mid 372.267734 -227.205645)
		(end 372.080536 -227.155502)
		(width 0.0889)
		(layer "B.Cu")
		(net "I3C_SPD_DDREFGH_CPU0_SCL")
	)
	(arc
		(start 372.070122 -227.149406)
		(mid 371.79169 -227.07956)
		(end 371.514878 -227.155502)
		(width 0.0889)
		(layer "B.Cu")
		(net "I3C_SPD_DDREFGH_CPU0_SCL")
	)
	(arc
		(start 382.407668 -227.149406)
		(mid 382.12949 -227.079683)
		(end 381.852932 -227.155502)
		(width 0.0889)
		(layer "B.Cu")
		(net "I3C_SPD_DDREFGH_CPU0_SCL")
	)
	(arc
		(start 384.672332 -227.155502)
		(mid 384.485134 -227.205645)
		(end 384.297936 -227.155502)
		(width 0.0889)
		(layer "B.Cu")
		(net "I3C_SPD_DDREFGH_CPU0_SCL")
	)
	(arc
		(start 379.588268 -227.149406)
		(mid 379.31009 -227.079683)
		(end 379.033532 -227.155502)
		(width 0.0889)
		(layer "B.Cu")
		(net "I3C_SPD_DDREFGH_CPU0_SCL")
	)
	(arc
		(start 377.153678 -227.155502)
		(mid 376.96648 -227.205645)
		(end 376.779282 -227.155502)
		(width 0.0889)
		(layer "B.Cu")
		(net "I3C_SPD_DDREFGH_CPU0_SCL")
	)
	(arc
		(start 370.200682 -227.155502)
		(mid 369.924123 -227.079759)
		(end 369.645946 -227.149406)
		(width 0.0889)
		(layer "B.Cu")
		(net "I3C_SPD_DDREFGH_CPU0_SCL")
	)
	(arc
		(start 373.009668 -227.149406)
		(mid 372.73149 -227.079683)
		(end 372.454932 -227.155502)
		(width 0.0889)
		(layer "B.Cu")
		(net "I3C_SPD_DDREFGH_CPU0_SCL")
	)
	(arc
		(start 378.093478 -227.155502)
		(mid 377.90628 -227.205645)
		(end 377.719082 -227.155502)
		(width 0.0889)
		(layer "B.Cu")
		(net "I3C_SPD_DDREFGH_CPU0_SCL")
	)
	(arc
		(start 377.70435 -227.146866)
		(mid 377.427875 -227.079546)
		(end 377.153678 -227.155502)
		(width 0.0889)
		(layer "B.Cu")
		(net "I3C_SPD_DDREFGH_CPU0_SCL")
	)
	(arc
		(start 371.514878 -227.155502)
		(mid 371.32768 -227.205645)
		(end 371.140482 -227.155502)
		(width 0.0889)
		(layer "B.Cu")
		(net "I3C_SPD_DDREFGH_CPU0_SCL")
	)
	(arc
		(start 379.973078 -227.155502)
		(mid 379.78588 -227.205645)
		(end 379.598682 -227.155502)
		(width 0.0889)
		(layer "B.Cu")
		(net "I3C_SPD_DDREFGH_CPU0_SCL")
	)
	(arc
		(start 383.732532 -227.155502)
		(mid 383.545334 -227.205645)
		(end 383.358136 -227.155502)
		(width 0.0889)
		(layer "B.Cu")
		(net "I3C_SPD_DDREFGH_CPU0_SCL")
	)
	(arc
		(start 379.033532 -227.155502)
		(mid 378.846334 -227.205645)
		(end 378.659136 -227.155502)
		(width 0.0889)
		(layer "B.Cu")
		(net "I3C_SPD_DDREFGH_CPU0_SCL")
	)
	(arc
		(start 371.12575 -227.146866)
		(mid 370.849275 -227.079546)
		(end 370.575078 -227.155502)
		(width 0.0889)
		(layer "B.Cu")
		(net "I3C_SPD_DDREFGH_CPU0_SCL")
	)
	(arc
		(start 376.779282 -227.155502)
		(mid 376.502723 -227.079759)
		(end 376.224546 -227.149406)
		(width 0.0889)
		(layer "B.Cu")
		(net "I3C_SPD_DDREFGH_CPU0_SCL")
	)
	(arc
		(start 373.394478 -227.155502)
		(mid 373.20728 -227.205645)
		(end 373.020082 -227.155502)
		(width 0.0889)
		(layer "B.Cu")
		(net "I3C_SPD_DDREFGH_CPU0_SCL")
	)
	(arc
		(start 374.334278 -227.155502)
		(mid 374.14708 -227.205645)
		(end 373.959882 -227.155502)
		(width 0.0889)
		(layer "B.Cu")
		(net "I3C_SPD_DDREFGH_CPU0_SCL")
	)
	(arc
		(start 381.852932 -227.155502)
		(mid 381.665734 -227.205645)
		(end 381.478536 -227.155502)
		(width 0.0889)
		(layer "B.Cu")
		(net "I3C_SPD_DDREFGH_CPU0_SCL")
	)
	(arc
		(start 369.635532 -227.155502)
		(mid 369.448334 -227.205645)
		(end 369.261136 -227.155502)
		(width 0.0889)
		(layer "B.Cu")
		(net "I3C_SPD_DDREFGH_CPU0_SCL")
	)
	(arc
		(start 370.575078 -227.155502)
		(mid 370.38788 -227.205645)
		(end 370.200682 -227.155502)
		(width 0.0889)
		(layer "B.Cu")
		(net "I3C_SPD_DDREFGH_CPU0_SCL")
	)
	(arc
		(start 378.648722 -227.149406)
		(mid 378.37029 -227.07956)
		(end 378.093478 -227.155502)
		(width 0.0889)
		(layer "B.Cu")
		(net "I3C_SPD_DDREFGH_CPU0_SCL")
	)
	(via
		(at 302.990758 -151.133048)
		(size 0.6604)
		(drill 0.3302)
		(layers "F.Cu" "B.Cu")
		(net "I3C_SPD_DDREFGH_CPU0_R_SDA")
	)
	(segment
		(start 378.464064 -188.720476)
		(end 378.464064 -184.877202)
		(width 0.12954)
		(layer "B.Cu")
		(net "I3C_SPD_DDREFGH_CPU0_R_SDA")
	)
	(segment
		(start 304.165508 -151.346408)
		(end 304.138584 -151.319484)
		(width 0.12954)
		(layer "B.Cu")
		(net "I3C_SPD_DDREFGH_CPU0_R_SDA")
	)
	(segment
		(start 303.952148 -151.133048)
		(end 302.990758 -151.133048)
		(width 0.12954)
		(layer "B.Cu")
		(net "I3C_SPD_DDREFGH_CPU0_R_SDA")
	)
	(segment
		(start 321.883786 -150.439628)
		(end 307.68798 -150.439628)
		(width 0.12954)
		(layer "B.Cu")
		(net "I3C_SPD_DDREFGH_CPU0_R_SDA")
	)
	(segment
		(start 355.136704 -174.166276)
		(end 353.150678 -173.34357)
		(width 0.12954)
		(layer "B.Cu")
		(net "I3C_SPD_DDREFGH_CPU0_R_SDA")
	)
	(segment
		(start 346.467938 -171.48683)
		(end 327.92162 -152.940512)
		(width 0.12954)
		(layer "B.Cu")
		(net "I3C_SPD_DDREFGH_CPU0_R_SDA")
	)
	(segment
		(start 302.169068 -151.086058)
		(end 301.258732 -151.086058)
		(width 0.12954)
		(layer "B.Cu")
		(net "I3C_SPD_DDREFGH_CPU0_R_SDA")
	)
	(segment
		(start 359.063798 -174.71517)
		(end 355.685598 -174.71517)
		(width 0.12954)
		(layer "B.Cu")
		(net "I3C_SPD_DDREFGH_CPU0_R_SDA")
	)
	(segment
		(start 368.308382 -180.195982)
		(end 368.308382 -179.563014)
		(width 0.12954)
		(layer "B.Cu")
		(net "I3C_SPD_DDREFGH_CPU0_R_SDA")
	)
	(segment
		(start 379.720602 -189.977014)
		(end 378.464064 -188.720476)
		(width 0.12954)
		(layer "B.Cu")
		(net "I3C_SPD_DDREFGH_CPU0_R_SDA")
	)
	(segment
		(start 374.960642 -181.37378)
		(end 373.326406 -180.69687)
		(width 0.12954)
		(layer "B.Cu")
		(net "I3C_SPD_DDREFGH_CPU0_R_SDA")
	)
	(segment
		(start 351.293938 -171.48683)
		(end 346.467938 -171.48683)
		(width 0.12954)
		(layer "B.Cu")
		(net "I3C_SPD_DDREFGH_CPU0_R_SDA")
	)
	(segment
		(start 327.92162 -152.940512)
		(end 321.883786 -150.439628)
		(width 0.12954)
		(layer "B.Cu")
		(net "I3C_SPD_DDREFGH_CPU0_R_SDA")
	)
	(segment
		(start 370.260118 -181.08803)
		(end 369.20043 -181.08803)
		(width 0.12954)
		(layer "B.Cu")
		(net "I3C_SPD_DDREFGH_CPU0_R_SDA")
	)
	(segment
		(start 307.68798 -150.439628)
		(end 306.7812 -151.346408)
		(width 0.12954)
		(layer "B.Cu")
		(net "I3C_SPD_DDREFGH_CPU0_R_SDA")
	)
	(segment
		(start 378.464064 -184.877202)
		(end 374.960642 -181.37378)
		(width 0.12954)
		(layer "B.Cu")
		(net "I3C_SPD_DDREFGH_CPU0_R_SDA")
	)
	(segment
		(start 368.308382 -179.563014)
		(end 365.238792 -176.493424)
		(width 0.12954)
		(layer "B.Cu")
		(net "I3C_SPD_DDREFGH_CPU0_R_SDA")
	)
	(segment
		(start 365.238792 -176.493424)
		(end 360.842052 -176.493424)
		(width 0.12954)
		(layer "B.Cu")
		(net "I3C_SPD_DDREFGH_CPU0_R_SDA")
	)
	(segment
		(start 355.685598 -174.71517)
		(end 355.136704 -174.166276)
		(width 0.12954)
		(layer "B.Cu")
		(net "I3C_SPD_DDREFGH_CPU0_R_SDA")
	)
	(segment
		(start 353.150678 -173.34357)
		(end 351.293938 -171.48683)
		(width 0.12954)
		(layer "B.Cu")
		(net "I3C_SPD_DDREFGH_CPU0_R_SDA")
	)
	(segment
		(start 370.651278 -180.69687)
		(end 370.260118 -181.08803)
		(width 0.12954)
		(layer "B.Cu")
		(net "I3C_SPD_DDREFGH_CPU0_R_SDA")
	)
	(segment
		(start 304.138584 -151.319484)
		(end 303.952148 -151.133048)
		(width 0.12954)
		(layer "B.Cu")
		(net "I3C_SPD_DDREFGH_CPU0_R_SDA")
	)
	(segment
		(start 302.216058 -151.133048)
		(end 302.169068 -151.086058)
		(width 0.12954)
		(layer "B.Cu")
		(net "I3C_SPD_DDREFGH_CPU0_R_SDA")
	)
	(segment
		(start 379.720602 -190.395098)
		(end 379.720602 -189.977014)
		(width 0.12954)
		(layer "B.Cu")
		(net "I3C_SPD_DDREFGH_CPU0_R_SDA")
	)
	(segment
		(start 373.326406 -180.69687)
		(end 370.651278 -180.69687)
		(width 0.12954)
		(layer "B.Cu")
		(net "I3C_SPD_DDREFGH_CPU0_R_SDA")
	)
	(segment
		(start 306.7812 -151.346408)
		(end 304.165508 -151.346408)
		(width 0.12954)
		(layer "B.Cu")
		(net "I3C_SPD_DDREFGH_CPU0_R_SDA")
	)
	(segment
		(start 360.842052 -176.493424)
		(end 359.063798 -174.71517)
		(width 0.12954)
		(layer "B.Cu")
		(net "I3C_SPD_DDREFGH_CPU0_R_SDA")
	)
	(segment
		(start 302.990758 -151.133048)
		(end 302.216058 -151.133048)
		(width 0.12954)
		(layer "B.Cu")
		(net "I3C_SPD_DDREFGH_CPU0_R_SDA")
	)
	(segment
		(start 369.20043 -181.08803)
		(end 368.308382 -180.195982)
		(width 0.12954)
		(layer "B.Cu")
		(net "I3C_SPD_DDREFGH_CPU0_R_SDA")
	)
	(via
		(at 302.993298 -153.835608)
		(size 0.6604)
		(drill 0.3302)
		(layers "F.Cu" "B.Cu")
		(net "I3C_SPD_DDREFGH_CPU0_R_SCL")
	)
	(segment
		(start 304.138584 -153.101294)
		(end 303.727612 -153.101294)
		(width 0.12954)
		(layer "B.Cu")
		(net "I3C_SPD_DDREFGH_CPU0_R_SCL")
	)
	(segment
		(start 376.618754 -190.303658)
		(end 376.618754 -186.694826)
		(width 0.12954)
		(layer "B.Cu")
		(net "I3C_SPD_DDREFGH_CPU0_R_SCL")
	)
	(segment
		(start 307.69052 -151.37511)
		(end 307.69052 -152.240234)
		(width 0.12954)
		(layer "B.Cu")
		(net "I3C_SPD_DDREFGH_CPU0_R_SCL")
	)
	(segment
		(start 352.689922 -173.891194)
		(end 351.027238 -172.22851)
		(width 0.12954)
		(layer "B.Cu")
		(net "I3C_SPD_DDREFGH_CPU0_R_SCL")
	)
	(segment
		(start 367.608358 -179.87391)
		(end 364.972092 -177.237644)
		(width 0.12954)
		(layer "B.Cu")
		(net "I3C_SPD_DDREFGH_CPU0_R_SCL")
	)
	(segment
		(start 327.545954 -153.537666)
		(end 321.667632 -151.102568)
		(width 0.12954)
		(layer "B.Cu")
		(net "I3C_SPD_DDREFGH_CPU0_R_SCL")
	)
	(segment
		(start 357.214932 -177.237644)
		(end 354.701856 -174.724568)
		(width 0.12954)
		(layer "B.Cu")
		(net "I3C_SPD_DDREFGH_CPU0_R_SCL")
	)
	(segment
		(start 306.82946 -153.101294)
		(end 304.138584 -153.101294)
		(width 0.12954)
		(layer "B.Cu")
		(net "I3C_SPD_DDREFGH_CPU0_R_SCL")
	)
	(segment
		(start 303.727612 -153.101294)
		(end 302.993298 -153.835608)
		(width 0.12954)
		(layer "B.Cu")
		(net "I3C_SPD_DDREFGH_CPU0_R_SCL")
	)
	(segment
		(start 307.963062 -151.102568)
		(end 307.69052 -151.37511)
		(width 0.12954)
		(layer "B.Cu")
		(net "I3C_SPD_DDREFGH_CPU0_R_SCL")
	)
	(segment
		(start 376.618754 -186.694826)
		(end 374.362218 -184.43829)
		(width 0.12954)
		(layer "B.Cu")
		(net "I3C_SPD_DDREFGH_CPU0_R_SCL")
	)
	(segment
		(start 354.701856 -174.724568)
		(end 352.689922 -173.891194)
		(width 0.12954)
		(layer "B.Cu")
		(net "I3C_SPD_DDREFGH_CPU0_R_SCL")
	)
	(segment
		(start 371.755162 -182.96255)
		(end 369.089178 -182.96255)
		(width 0.12954)
		(layer "B.Cu")
		(net "I3C_SPD_DDREFGH_CPU0_R_SCL")
	)
	(segment
		(start 302.148748 -152.991058)
		(end 301.258732 -152.991058)
		(width 0.12954)
		(layer "B.Cu")
		(net "I3C_SPD_DDREFGH_CPU0_R_SCL")
	)
	(segment
		(start 364.972092 -177.237644)
		(end 357.214932 -177.237644)
		(width 0.12954)
		(layer "B.Cu")
		(net "I3C_SPD_DDREFGH_CPU0_R_SCL")
	)
	(segment
		(start 307.69052 -152.240234)
		(end 306.82946 -153.101294)
		(width 0.12954)
		(layer "B.Cu")
		(net "I3C_SPD_DDREFGH_CPU0_R_SCL")
	)
	(segment
		(start 374.362218 -184.43829)
		(end 372.430802 -183.63819)
		(width 0.12954)
		(layer "B.Cu")
		(net "I3C_SPD_DDREFGH_CPU0_R_SCL")
	)
	(segment
		(start 346.236798 -172.22851)
		(end 327.545954 -153.537666)
		(width 0.12954)
		(layer "B.Cu")
		(net "I3C_SPD_DDREFGH_CPU0_R_SCL")
	)
	(segment
		(start 369.089178 -182.96255)
		(end 367.608358 -181.48173)
		(width 0.12954)
		(layer "B.Cu")
		(net "I3C_SPD_DDREFGH_CPU0_R_SCL")
	)
	(segment
		(start 302.993298 -153.835608)
		(end 302.148748 -152.991058)
		(width 0.12954)
		(layer "B.Cu")
		(net "I3C_SPD_DDREFGH_CPU0_R_SCL")
	)
	(segment
		(start 321.667632 -151.102568)
		(end 307.963062 -151.102568)
		(width 0.12954)
		(layer "B.Cu")
		(net "I3C_SPD_DDREFGH_CPU0_R_SCL")
	)
	(segment
		(start 351.027238 -172.22851)
		(end 346.236798 -172.22851)
		(width 0.12954)
		(layer "B.Cu")
		(net "I3C_SPD_DDREFGH_CPU0_R_SCL")
	)
	(segment
		(start 367.608358 -181.48173)
		(end 367.608358 -179.87391)
		(width 0.12954)
		(layer "B.Cu")
		(net "I3C_SPD_DDREFGH_CPU0_R_SCL")
	)
	(segment
		(start 372.430802 -183.63819)
		(end 371.755162 -182.96255)
		(width 0.12954)
		(layer "B.Cu")
		(net "I3C_SPD_DDREFGH_CPU0_R_SCL")
	)
	(segment
		(start 410.031946 -317.590932)
		(end 409.876498 -317.590932)
		(width 0.12954)
		(layer "F.Cu")
		(net "I3C_SPD_DDREFGH_CPU0_LVC1_SDA")
	)
	(segment
		(start 460.723488 -318.016636)
		(end 459.559914 -318.016636)
		(width 0.12954)
		(layer "F.Cu")
		(net "I3C_SPD_DDREFGH_CPU0_LVC1_SDA")
	)
	(segment
		(start 409.84678 -317.62065)
		(end 409.45054 -317.62065)
		(width 0.12954)
		(layer "F.Cu")
		(net "I3C_SPD_DDREFGH_CPU0_LVC1_SDA")
	)
	(segment
		(start 436.928514 -318.016636)
		(end 435.207918 -318.016636)
		(width 0.12954)
		(layer "F.Cu")
		(net "I3C_SPD_DDREFGH_CPU0_LVC1_SDA")
	)
	(segment
		(start 407.651712 -318.016636)
		(end 406.753314 -318.016636)
		(width 0.12954)
		(layer "F.Cu")
		(net "I3C_SPD_DDREFGH_CPU0_LVC1_SDA")
	)
	(segment
		(start 459.559914 -318.016636)
		(end 458.154278 -318.016636)
		(width 0.12954)
		(layer "F.Cu")
		(net "I3C_SPD_DDREFGH_CPU0_LVC1_SDA")
	)
	(segment
		(start 408.964638 -317.134748)
		(end 408.5336 -317.134748)
		(width 0.12954)
		(layer "F.Cu")
		(net "I3C_SPD_DDREFGH_CPU0_LVC1_SDA")
	)
	(segment
		(start 432.663346 -317.590932)
		(end 431.575464 -317.590932)
		(width 0.12954)
		(layer "F.Cu")
		(net "I3C_SPD_DDREFGH_CPU0_LVC1_SDA")
	)
	(segment
		(start 424.04665 -317.590932)
		(end 423.620946 -318.016636)
		(width 0.12954)
		(layer "F.Cu")
		(net "I3C_SPD_DDREFGH_CPU0_LVC1_SDA")
	)
	(segment
		(start 409.876498 -317.590932)
		(end 409.84678 -317.62065)
		(width 0.12954)
		(layer "F.Cu")
		(net "I3C_SPD_DDREFGH_CPU0_LVC1_SDA")
	)
	(segment
		(start 464.469226 -317.590932)
		(end 462.838546 -317.590932)
		(width 0.1016)
		(layer "F.Cu")
		(net "I3C_SPD_DDREFGH_CPU0_LVC1_SDA")
	)
	(segment
		(start 416.321748 -318.015112)
		(end 414.298638 -318.015112)
		(width 0.12954)
		(layer "F.Cu")
		(net "I3C_SPD_DDREFGH_CPU0_LVC1_SDA")
	)
	(segment
		(start 450.392038 -317.590932)
		(end 449.409566 -317.590932)
		(width 0.12954)
		(layer "F.Cu")
		(net "I3C_SPD_DDREFGH_CPU0_LVC1_SDA")
	)
	(segment
		(start 439.337704 -317.590932)
		(end 438.912 -318.016636)
		(width 0.12954)
		(layer "F.Cu")
		(net "I3C_SPD_DDREFGH_CPU0_LVC1_SDA")
	)
	(segment
		(start 414.298638 -318.015112)
		(end 414.297114 -318.016636)
		(width 0.12954)
		(layer "F.Cu")
		(net "I3C_SPD_DDREFGH_CPU0_LVC1_SDA")
	)
	(segment
		(start 419.332918 -318.44107)
		(end 419.170866 -318.44107)
		(width 0.12954)
		(layer "F.Cu")
		(net "I3C_SPD_DDREFGH_CPU0_LVC1_SDA")
	)
	(segment
		(start 446.0494 -318.016636)
		(end 444.472314 -318.016636)
		(width 0.12954)
		(layer "F.Cu")
		(net "I3C_SPD_DDREFGH_CPU0_LVC1_SDA")
	)
	(segment
		(start 434.311806 -317.590932)
		(end 432.663346 -317.590932)
		(width 0.1016)
		(layer "F.Cu")
		(net "I3C_SPD_DDREFGH_CPU0_LVC1_SDA")
	)
	(segment
		(start 457.728574 -317.590932)
		(end 456.925426 -317.590932)
		(width 0.12954)
		(layer "F.Cu")
		(net "I3C_SPD_DDREFGH_CPU0_LVC1_SDA")
	)
	(segment
		(start 461.149192 -317.590932)
		(end 460.723488 -318.016636)
		(width 0.12954)
		(layer "F.Cu")
		(net "I3C_SPD_DDREFGH_CPU0_LVC1_SDA")
	)
	(segment
		(start 455.294746 -317.590932)
		(end 453.932544 -317.590932)
		(width 0.12954)
		(layer "F.Cu")
		(net "I3C_SPD_DDREFGH_CPU0_LVC1_SDA")
	)
	(segment
		(start 428.233586 -318.016636)
		(end 427.807882 -317.590932)
		(width 0.12954)
		(layer "F.Cu")
		(net "I3C_SPD_DDREFGH_CPU0_LVC1_SDA")
	)
	(segment
		(start 411.672786 -317.590932)
		(end 410.031946 -317.590932)
		(width 0.1016)
		(layer "F.Cu")
		(net "I3C_SPD_DDREFGH_CPU0_LVC1_SDA")
	)
	(segment
		(start 453.50684 -318.016636)
		(end 452.016114 -318.016636)
		(width 0.12954)
		(layer "F.Cu")
		(net "I3C_SPD_DDREFGH_CPU0_LVC1_SDA")
	)
	(segment
		(start 419.757352 -318.016636)
		(end 419.332918 -318.44107)
		(width 0.12954)
		(layer "F.Cu")
		(net "I3C_SPD_DDREFGH_CPU0_LVC1_SDA")
	)
	(segment
		(start 412.726378 -317.590932)
		(end 411.672786 -317.590932)
		(width 0.12954)
		(layer "F.Cu")
		(net "I3C_SPD_DDREFGH_CPU0_LVC1_SDA")
	)
	(segment
		(start 435.207918 -318.016636)
		(end 434.782214 -317.590932)
		(width 0.12954)
		(layer "F.Cu")
		(net "I3C_SPD_DDREFGH_CPU0_LVC1_SDA")
	)
	(segment
		(start 409.45054 -317.62065)
		(end 408.964638 -317.134748)
		(width 0.12954)
		(layer "F.Cu")
		(net "I3C_SPD_DDREFGH_CPU0_LVC1_SDA")
	)
	(segment
		(start 423.620946 -318.016636)
		(end 421.840914 -318.016636)
		(width 0.12954)
		(layer "F.Cu")
		(net "I3C_SPD_DDREFGH_CPU0_LVC1_SDA")
	)
	(segment
		(start 421.840914 -318.016636)
		(end 419.757352 -318.016636)
		(width 0.12954)
		(layer "F.Cu")
		(net "I3C_SPD_DDREFGH_CPU0_LVC1_SDA")
	)
	(segment
		(start 426.793406 -317.590932)
		(end 424.898566 -317.590932)
		(width 0.1016)
		(layer "F.Cu")
		(net "I3C_SPD_DDREFGH_CPU0_LVC1_SDA")
	)
	(segment
		(start 408.5336 -317.134748)
		(end 407.651712 -318.016636)
		(width 0.12954)
		(layer "F.Cu")
		(net "I3C_SPD_DDREFGH_CPU0_LVC1_SDA")
	)
	(segment
		(start 444.472314 -318.016636)
		(end 443.344554 -318.016636)
		(width 0.12954)
		(layer "F.Cu")
		(net "I3C_SPD_DDREFGH_CPU0_LVC1_SDA")
	)
	(segment
		(start 438.912 -318.016636)
		(end 436.928514 -318.016636)
		(width 0.12954)
		(layer "F.Cu")
		(net "I3C_SPD_DDREFGH_CPU0_LVC1_SDA")
	)
	(segment
		(start 447.750946 -317.590932)
		(end 446.475104 -317.590932)
		(width 0.12954)
		(layer "F.Cu")
		(net "I3C_SPD_DDREFGH_CPU0_LVC1_SDA")
	)
	(segment
		(start 440.207146 -317.590932)
		(end 439.337704 -317.590932)
		(width 0.12954)
		(layer "F.Cu")
		(net "I3C_SPD_DDREFGH_CPU0_LVC1_SDA")
	)
	(segment
		(start 414.297114 -318.016636)
		(end 413.152082 -318.016636)
		(width 0.12954)
		(layer "F.Cu")
		(net "I3C_SPD_DDREFGH_CPU0_LVC1_SDA")
	)
	(segment
		(start 441.858146 -317.590932)
		(end 440.207146 -317.590932)
		(width 0.1016)
		(layer "F.Cu")
		(net "I3C_SPD_DDREFGH_CPU0_LVC1_SDA")
	)
	(segment
		(start 416.753548 -318.446912)
		(end 416.321748 -318.015112)
		(width 0.12954)
		(layer "F.Cu")
		(net "I3C_SPD_DDREFGH_CPU0_LVC1_SDA")
	)
	(segment
		(start 442.91885 -317.590932)
		(end 441.858146 -317.590932)
		(width 0.12954)
		(layer "F.Cu")
		(net "I3C_SPD_DDREFGH_CPU0_LVC1_SDA")
	)
	(segment
		(start 427.807882 -317.590932)
		(end 426.793406 -317.590932)
		(width 0.12954)
		(layer "F.Cu")
		(net "I3C_SPD_DDREFGH_CPU0_LVC1_SDA")
	)
	(segment
		(start 417.575746 -318.44107)
		(end 417.569904 -318.446912)
		(width 0.12954)
		(layer "F.Cu")
		(net "I3C_SPD_DDREFGH_CPU0_LVC1_SDA")
	)
	(segment
		(start 450.817742 -318.016636)
		(end 450.392038 -317.590932)
		(width 0.12954)
		(layer "F.Cu")
		(net "I3C_SPD_DDREFGH_CPU0_LVC1_SDA")
	)
	(segment
		(start 417.569904 -318.446912)
		(end 416.753548 -318.446912)
		(width 0.12954)
		(layer "F.Cu")
		(net "I3C_SPD_DDREFGH_CPU0_LVC1_SDA")
	)
	(segment
		(start 443.344554 -318.016636)
		(end 442.91885 -317.590932)
		(width 0.12954)
		(layer "F.Cu")
		(net "I3C_SPD_DDREFGH_CPU0_LVC1_SDA")
	)
	(segment
		(start 452.016114 -318.016636)
		(end 450.817742 -318.016636)
		(width 0.12954)
		(layer "F.Cu")
		(net "I3C_SPD_DDREFGH_CPU0_LVC1_SDA")
	)
	(segment
		(start 446.475104 -317.590932)
		(end 446.0494 -318.016636)
		(width 0.12954)
		(layer "F.Cu")
		(net "I3C_SPD_DDREFGH_CPU0_LVC1_SDA")
	)
	(segment
		(start 449.409566 -317.590932)
		(end 447.750946 -317.590932)
		(width 0.1016)
		(layer "F.Cu")
		(net "I3C_SPD_DDREFGH_CPU0_LVC1_SDA")
	)
	(segment
		(start 453.932544 -317.590932)
		(end 453.50684 -318.016636)
		(width 0.12954)
		(layer "F.Cu")
		(net "I3C_SPD_DDREFGH_CPU0_LVC1_SDA")
	)
	(segment
		(start 424.898566 -317.590932)
		(end 424.04665 -317.590932)
		(width 0.12954)
		(layer "F.Cu")
		(net "I3C_SPD_DDREFGH_CPU0_LVC1_SDA")
	)
	(segment
		(start 458.154278 -318.016636)
		(end 457.728574 -317.590932)
		(width 0.12954)
		(layer "F.Cu")
		(net "I3C_SPD_DDREFGH_CPU0_LVC1_SDA")
	)
	(segment
		(start 464.916266 -317.590932)
		(end 464.469226 -317.590932)
		(width 0.12954)
		(layer "F.Cu")
		(net "I3C_SPD_DDREFGH_CPU0_LVC1_SDA")
	)
	(segment
		(start 429.384714 -318.016636)
		(end 428.233586 -318.016636)
		(width 0.12954)
		(layer "F.Cu")
		(net "I3C_SPD_DDREFGH_CPU0_LVC1_SDA")
	)
	(segment
		(start 456.925426 -317.590932)
		(end 455.294746 -317.590932)
		(width 0.1016)
		(layer "F.Cu")
		(net "I3C_SPD_DDREFGH_CPU0_LVC1_SDA")
	)
	(segment
		(start 462.838546 -317.590932)
		(end 461.149192 -317.590932)
		(width 0.12954)
		(layer "F.Cu")
		(net "I3C_SPD_DDREFGH_CPU0_LVC1_SDA")
	)
	(segment
		(start 434.782214 -317.590932)
		(end 434.311806 -317.590932)
		(width 0.12954)
		(layer "F.Cu")
		(net "I3C_SPD_DDREFGH_CPU0_LVC1_SDA")
	)
	(segment
		(start 413.152082 -318.016636)
		(end 412.726378 -317.590932)
		(width 0.12954)
		(layer "F.Cu")
		(net "I3C_SPD_DDREFGH_CPU0_LVC1_SDA")
	)
	(segment
		(start 431.575464 -317.590932)
		(end 431.14976 -318.016636)
		(width 0.12954)
		(layer "F.Cu")
		(net "I3C_SPD_DDREFGH_CPU0_LVC1_SDA")
	)
	(segment
		(start 419.170866 -318.44107)
		(end 417.575746 -318.44107)
		(width 0.1016)
		(layer "F.Cu")
		(net "I3C_SPD_DDREFGH_CPU0_LVC1_SDA")
	)
	(segment
		(start 431.14976 -318.016636)
		(end 429.384714 -318.016636)
		(width 0.12954)
		(layer "F.Cu")
		(net "I3C_SPD_DDREFGH_CPU0_LVC1_SDA")
	)
	(via
		(at 452.55688 -150.556468)
		(size 0.508)
		(drill 0.254)
		(layers "F.Cu" "B.Cu")
		(net "I3C_SPD_DDREFGH_CPU0_LVC1_SDA")
	)
	(via
		(at 307.08092 -152.009348)
		(size 0.508)
		(drill 0.254)
		(layers "F.Cu" "B.Cu")
		(net "I3C_SPD_DDREFGH_CPU0_LVC1_SDA")
	)
	(via
		(at 464.916266 -317.590932)
		(size 0.4572)
		(drill 0.2032)
		(layers "F.Cu" "B.Cu")
		(net "I3C_SPD_DDREFGH_CPU0_LVC1_SDA")
	)
	(segment
		(start 307.08092 -152.009348)
		(end 306.103782 -152.009348)
		(width 0.12954)
		(layer "B.Cu")
		(net "I3C_SPD_DDREFGH_CPU0_LVC1_SDA")
	)
	(segment
		(start 306.103782 -152.009348)
		(end 305.933348 -152.179782)
		(width 0.12954)
		(layer "B.Cu")
		(net "I3C_SPD_DDREFGH_CPU0_LVC1_SDA")
	)
	(segment
		(start 466.01126 -177.462688)
		(end 452.55688 -164.008308)
		(width 0.127)
		(layer "In2.Cu")
		(net "I3C_SPD_DDREFGH_CPU0_LVC1_SDA")
	)
	(segment
		(start 466.01126 -316.495938)
		(end 466.01126 -177.462688)
		(width 0.127)
		(layer "In2.Cu")
		(net "I3C_SPD_DDREFGH_CPU0_LVC1_SDA")
	)
	(segment
		(start 464.916266 -317.590932)
		(end 466.01126 -316.495938)
		(width 0.127)
		(layer "In2.Cu")
		(net "I3C_SPD_DDREFGH_CPU0_LVC1_SDA")
	)
	(segment
		(start 452.55688 -164.008308)
		(end 452.55688 -150.556468)
		(width 0.127)
		(layer "In2.Cu")
		(net "I3C_SPD_DDREFGH_CPU0_LVC1_SDA")
	)
	(segment
		(start 390.20496 -150.231348)
		(end 391.204196 -151.230584)
		(width 0.127)
		(layer "In13.Cu")
		(net "I3C_SPD_DDREFGH_CPU0_LVC1_SDA")
	)
	(segment
		(start 349.13316 -150.231348)
		(end 390.20496 -150.231348)
		(width 0.127)
		(layer "In13.Cu")
		(net "I3C_SPD_DDREFGH_CPU0_LVC1_SDA")
	)
	(segment
		(start 348.62516 -150.739348)
		(end 349.13316 -150.231348)
		(width 0.127)
		(layer "In13.Cu")
		(net "I3C_SPD_DDREFGH_CPU0_LVC1_SDA")
	)
	(segment
		(start 391.204196 -151.230584)
		(end 397.092424 -151.230584)
		(width 0.127)
		(layer "In13.Cu")
		(net "I3C_SPD_DDREFGH_CPU0_LVC1_SDA")
	)
	(segment
		(start 402.08708 -146.235928)
		(end 425.735496 -146.235928)
		(width 0.127)
		(layer "In13.Cu")
		(net "I3C_SPD_DDREFGH_CPU0_LVC1_SDA")
	)
	(segment
		(start 448.994022 -146.726148)
		(end 452.55688 -150.289006)
		(width 0.127)
		(layer "In13.Cu")
		(net "I3C_SPD_DDREFGH_CPU0_LVC1_SDA")
	)
	(segment
		(start 307.08092 -152.009348)
		(end 308.35092 -150.739348)
		(width 0.127)
		(layer "In13.Cu")
		(net "I3C_SPD_DDREFGH_CPU0_LVC1_SDA")
	)
	(segment
		(start 452.55688 -150.289006)
		(end 452.55688 -150.556468)
		(width 0.127)
		(layer "In13.Cu")
		(net "I3C_SPD_DDREFGH_CPU0_LVC1_SDA")
	)
	(segment
		(start 397.092424 -151.230584)
		(end 402.08708 -146.235928)
		(width 0.127)
		(layer "In13.Cu")
		(net "I3C_SPD_DDREFGH_CPU0_LVC1_SDA")
	)
	(segment
		(start 425.735496 -146.235928)
		(end 426.225716 -146.726148)
		(width 0.127)
		(layer "In13.Cu")
		(net "I3C_SPD_DDREFGH_CPU0_LVC1_SDA")
	)
	(segment
		(start 308.35092 -150.739348)
		(end 348.62516 -150.739348)
		(width 0.127)
		(layer "In13.Cu")
		(net "I3C_SPD_DDREFGH_CPU0_LVC1_SDA")
	)
	(segment
		(start 426.225716 -146.726148)
		(end 448.994022 -146.726148)
		(width 0.127)
		(layer "In13.Cu")
		(net "I3C_SPD_DDREFGH_CPU0_LVC1_SDA")
	)
	(via
		(at 454.246742 -315.409326)
		(size 0.4572)
		(drill 0.2032)
		(layers "F.Cu" "B.Cu")
		(net "I3C_SPD_DDREFGH_CPU0_LVC1_SCL")
	)
	(via
		(at 407.0731 -315.659008)
		(size 0.6604)
		(drill 0.3302)
		(layers "F.Cu" "B.Cu")
		(net "I3C_SPD_DDREFGH_CPU0_LVC1_SCL")
	)
	(via
		(at 438.668414 -317.166752)
		(size 0.4572)
		(drill 0.2032)
		(layers "F.Cu" "B.Cu")
		(net "I3C_SPD_DDREFGH_CPU0_LVC1_SCL")
	)
	(via
		(at 308.356 -152.212548)
		(size 0.508)
		(drill 0.254)
		(layers "F.Cu" "B.Cu")
		(net "I3C_SPD_DDREFGH_CPU0_LVC1_SCL")
	)
	(via
		(at 451.69074 -150.152608)
		(size 0.508)
		(drill 0.254)
		(layers "F.Cu" "B.Cu")
		(net "I3C_SPD_DDREFGH_CPU0_LVC1_SCL")
	)
	(via
		(at 461.026002 -313.208162)
		(size 0.4572)
		(drill 0.2032)
		(layers "F.Cu" "B.Cu")
		(net "I3C_SPD_DDREFGH_CPU0_LVC1_SCL")
	)
	(via
		(at 431.762408 -316.336172)
		(size 0.4572)
		(drill 0.2032)
		(layers "F.Cu" "B.Cu")
		(net "I3C_SPD_DDREFGH_CPU0_LVC1_SCL")
	)
	(via
		(at 446.258188 -316.898528)
		(size 0.4572)
		(drill 0.2032)
		(layers "F.Cu" "B.Cu")
		(net "I3C_SPD_DDREFGH_CPU0_LVC1_SCL")
	)
	(segment
		(start 415.916618 -316.221872)
		(end 414.41243 -316.221872)
		(width 0.12954)
		(layer "B.Cu")
		(net "I3C_SPD_DDREFGH_CPU0_LVC1_SCL")
	)
	(segment
		(start 446.006474 -316.308994)
		(end 444.42126 -316.308994)
		(width 0.12954)
		(layer "B.Cu")
		(net "I3C_SPD_DDREFGH_CPU0_LVC1_SCL")
	)
	(segment
		(start 430.440846 -316.32017)
		(end 429.767746 -316.99327)
		(width 0.12954)
		(layer "B.Cu")
		(net "I3C_SPD_DDREFGH_CPU0_LVC1_SCL")
	)
	(segment
		(start 452.867268 -316.75578)
		(end 451.812406 -316.75578)
		(width 0.12954)
		(layer "B.Cu")
		(net "I3C_SPD_DDREFGH_CPU0_LVC1_SCL")
	)
	(segment
		(start 407.0731 -315.659008)
		(end 407.0731 -315.33465)
		(width 0.12954)
		(layer "B.Cu")
		(net "I3C_SPD_DDREFGH_CPU0_LVC1_SCL")
	)
	(segment
		(start 308.356 -152.212548)
		(end 308.356 -152.745948)
		(width 0.12954)
		(layer "B.Cu")
		(net "I3C_SPD_DDREFGH_CPU0_LVC1_SCL")
	)
	(segment
		(start 461.35544 -313.5376)
		(end 461.35544 -314.372244)
		(width 0.12954)
		(layer "B.Cu")
		(net "I3C_SPD_DDREFGH_CPU0_LVC1_SCL")
	)
	(segment
		(start 461.026002 -313.208162)
		(end 461.35544 -313.5376)
		(width 0.12954)
		(layer "B.Cu")
		(net "I3C_SPD_DDREFGH_CPU0_LVC1_SCL")
	)
	(segment
		(start 429.16856 -316.99327)
		(end 428.293276 -316.117986)
		(width 0.12954)
		(layer "B.Cu")
		(net "I3C_SPD_DDREFGH_CPU0_LVC1_SCL")
	)
	(segment
		(start 438.668414 -317.429388)
		(end 438.429146 -317.668656)
		(width 0.12954)
		(layer "B.Cu")
		(net "I3C_SPD_DDREFGH_CPU0_LVC1_SCL")
	)
	(segment
		(start 419.724332 -315.670184)
		(end 416.468306 -315.670184)
		(width 0.12954)
		(layer "B.Cu")
		(net "I3C_SPD_DDREFGH_CPU0_LVC1_SCL")
	)
	(segment
		(start 431.746406 -316.32017)
		(end 430.440846 -316.32017)
		(width 0.12954)
		(layer "B.Cu")
		(net "I3C_SPD_DDREFGH_CPU0_LVC1_SCL")
	)
	(segment
		(start 425.619418 -315.864748)
		(end 424.49115 -315.864748)
		(width 0.12954)
		(layer "B.Cu")
		(net "I3C_SPD_DDREFGH_CPU0_LVC1_SCL")
	)
	(segment
		(start 429.391572 -316.99327)
		(end 429.16856 -316.99327)
		(width 0.12954)
		(layer "B.Cu")
		(net "I3C_SPD_DDREFGH_CPU0_LVC1_SCL")
	)
	(segment
		(start 420.878254 -317.65494)
		(end 420.152322 -317.65494)
		(width 0.12954)
		(layer "B.Cu")
		(net "I3C_SPD_DDREFGH_CPU0_LVC1_SCL")
	)
	(segment
		(start 308.356 -152.745948)
		(end 307.278278 -153.82367)
		(width 0.12954)
		(layer "B.Cu")
		(net "I3C_SPD_DDREFGH_CPU0_LVC1_SCL")
	)
	(segment
		(start 437.463438 -317.448946)
		(end 436.926482 -317.448946)
		(width 0.12954)
		(layer "B.Cu")
		(net "I3C_SPD_DDREFGH_CPU0_LVC1_SCL")
	)
	(segment
		(start 407.0731 -315.33465)
		(end 407.568908 -314.838842)
		(width 0.12954)
		(layer "B.Cu")
		(net "I3C_SPD_DDREFGH_CPU0_LVC1_SCL")
	)
	(segment
		(start 412.919164 -316.1284)
		(end 414.318958 -316.1284)
		(width 0.12954)
		(layer "B.Cu")
		(net "I3C_SPD_DDREFGH_CPU0_LVC1_SCL")
	)
	(segment
		(start 414.318958 -316.1284)
		(end 414.41243 -316.221872)
		(width 0.12954)
		(layer "B.Cu")
		(net "I3C_SPD_DDREFGH_CPU0_LVC1_SCL")
	)
	(segment
		(start 409.604464 -315.457078)
		(end 412.247842 -315.457078)
		(width 0.12954)
		(layer "B.Cu")
		(net "I3C_SPD_DDREFGH_CPU0_LVC1_SCL")
	)
	(segment
		(start 307.278278 -153.82367)
		(end 306.024788 -153.82367)
		(width 0.12954)
		(layer "B.Cu")
		(net "I3C_SPD_DDREFGH_CPU0_LVC1_SCL")
	)
	(segment
		(start 437.683148 -317.668656)
		(end 437.463438 -317.448946)
		(width 0.12954)
		(layer "B.Cu")
		(net "I3C_SPD_DDREFGH_CPU0_LVC1_SCL")
	)
	(segment
		(start 421.418766 -317.114428)
		(end 420.878254 -317.65494)
		(width 0.12954)
		(layer "B.Cu")
		(net "I3C_SPD_DDREFGH_CPU0_LVC1_SCL")
	)
	(segment
		(start 427.59503 -315.734192)
		(end 425.749974 -315.734192)
		(width 0.12954)
		(layer "B.Cu")
		(net "I3C_SPD_DDREFGH_CPU0_LVC1_SCL")
	)
	(segment
		(start 454.246742 -315.409326)
		(end 454.213722 -315.409326)
		(width 0.12954)
		(layer "B.Cu")
		(net "I3C_SPD_DDREFGH_CPU0_LVC1_SCL")
	)
	(segment
		(start 438.668414 -317.166752)
		(end 438.668414 -317.429388)
		(width 0.12954)
		(layer "B.Cu")
		(net "I3C_SPD_DDREFGH_CPU0_LVC1_SCL")
	)
	(segment
		(start 420.152322 -316.098174)
		(end 419.724332 -315.670184)
		(width 0.12954)
		(layer "B.Cu")
		(net "I3C_SPD_DDREFGH_CPU0_LVC1_SCL")
	)
	(segment
		(start 407.0731 -316.85103)
		(end 407.0731 -315.659008)
		(width 0.12954)
		(layer "B.Cu")
		(net "I3C_SPD_DDREFGH_CPU0_LVC1_SCL")
	)
	(segment
		(start 446.258188 -316.898528)
		(end 446.258188 -316.560708)
		(width 0.12954)
		(layer "B.Cu")
		(net "I3C_SPD_DDREFGH_CPU0_LVC1_SCL")
	)
	(segment
		(start 412.247842 -315.457078)
		(end 412.919164 -316.1284)
		(width 0.12954)
		(layer "B.Cu")
		(net "I3C_SPD_DDREFGH_CPU0_LVC1_SCL")
	)
	(segment
		(start 424.22191 -316.133988)
		(end 423.086784 -316.133988)
		(width 0.12954)
		(layer "B.Cu")
		(net "I3C_SPD_DDREFGH_CPU0_LVC1_SCL")
	)
	(segment
		(start 422.106344 -317.114428)
		(end 421.418766 -317.114428)
		(width 0.12954)
		(layer "B.Cu")
		(net "I3C_SPD_DDREFGH_CPU0_LVC1_SCL")
	)
	(segment
		(start 408.986228 -314.838842)
		(end 409.604464 -315.457078)
		(width 0.12954)
		(layer "B.Cu")
		(net "I3C_SPD_DDREFGH_CPU0_LVC1_SCL")
	)
	(segment
		(start 407.568908 -314.838842)
		(end 408.986228 -314.838842)
		(width 0.12954)
		(layer "B.Cu")
		(net "I3C_SPD_DDREFGH_CPU0_LVC1_SCL")
	)
	(segment
		(start 424.49115 -315.864748)
		(end 424.22191 -316.133988)
		(width 0.12954)
		(layer "B.Cu")
		(net "I3C_SPD_DDREFGH_CPU0_LVC1_SCL")
	)
	(segment
		(start 428.293276 -316.117986)
		(end 427.978824 -316.117986)
		(width 0.12954)
		(layer "B.Cu")
		(net "I3C_SPD_DDREFGH_CPU0_LVC1_SCL")
	)
	(segment
		(start 431.762408 -316.336172)
		(end 431.746406 -316.32017)
		(width 0.12954)
		(layer "B.Cu")
		(net "I3C_SPD_DDREFGH_CPU0_LVC1_SCL")
	)
	(segment
		(start 454.213722 -315.409326)
		(end 452.867268 -316.75578)
		(width 0.12954)
		(layer "B.Cu")
		(net "I3C_SPD_DDREFGH_CPU0_LVC1_SCL")
	)
	(segment
		(start 416.468306 -315.670184)
		(end 415.916618 -316.221872)
		(width 0.12954)
		(layer "B.Cu")
		(net "I3C_SPD_DDREFGH_CPU0_LVC1_SCL")
	)
	(segment
		(start 427.978824 -316.117986)
		(end 427.59503 -315.734192)
		(width 0.12954)
		(layer "B.Cu")
		(net "I3C_SPD_DDREFGH_CPU0_LVC1_SCL")
	)
	(segment
		(start 425.749974 -315.734192)
		(end 425.619418 -315.864748)
		(width 0.12954)
		(layer "B.Cu")
		(net "I3C_SPD_DDREFGH_CPU0_LVC1_SCL")
	)
	(segment
		(start 423.086784 -316.133988)
		(end 422.106344 -317.114428)
		(width 0.12954)
		(layer "B.Cu")
		(net "I3C_SPD_DDREFGH_CPU0_LVC1_SCL")
	)
	(segment
		(start 420.152322 -317.65494)
		(end 420.152322 -316.098174)
		(width 0.12954)
		(layer "B.Cu")
		(net "I3C_SPD_DDREFGH_CPU0_LVC1_SCL")
	)
	(segment
		(start 429.767746 -316.99327)
		(end 429.391572 -316.99327)
		(width 0.12954)
		(layer "B.Cu")
		(net "I3C_SPD_DDREFGH_CPU0_LVC1_SCL")
	)
	(segment
		(start 438.429146 -317.668656)
		(end 437.683148 -317.668656)
		(width 0.12954)
		(layer "B.Cu")
		(net "I3C_SPD_DDREFGH_CPU0_LVC1_SCL")
	)
	(segment
		(start 446.258188 -316.560708)
		(end 446.006474 -316.308994)
		(width 0.12954)
		(layer "B.Cu")
		(net "I3C_SPD_DDREFGH_CPU0_LVC1_SCL")
	)
	(segment
		(start 459.433422 -313.564778)
		(end 460.153004 -313.564778)
		(width 0.127)
		(layer "In2.Cu")
		(net "I3C_SPD_DDREFGH_CPU0_LVC1_SCL")
	)
	(segment
		(start 453.145398 -316.14491)
		(end 453.880982 -315.409326)
		(width 0.127)
		(layer "In2.Cu")
		(net "I3C_SPD_DDREFGH_CPU0_LVC1_SCL")
	)
	(segment
		(start 439.467244 -322.019168)
		(end 441.578238 -322.019168)
		(width 0.127)
		(layer "In2.Cu")
		(net "I3C_SPD_DDREFGH_CPU0_LVC1_SCL")
	)
	(segment
		(start 450.192394 -317.424308)
		(end 450.544184 -317.776098)
		(width 0.127)
		(layer "In2.Cu")
		(net "I3C_SPD_DDREFGH_CPU0_LVC1_SCL")
	)
	(segment
		(start 461.418686 -313.208162)
		(end 462.18348 -312.443368)
		(width 0.127)
		(layer "In2.Cu")
		(net "I3C_SPD_DDREFGH_CPU0_LVC1_SCL")
	)
	(segment
		(start 446.258188 -316.898528)
		(end 446.53708 -316.898528)
		(width 0.127)
		(layer "In2.Cu")
		(net "I3C_SPD_DDREFGH_CPU0_LVC1_SCL")
	)
	(segment
		(start 445.290448 -318.127634)
		(end 446.258188 -317.159894)
		(width 0.127)
		(layer "In2.Cu")
		(net "I3C_SPD_DDREFGH_CPU0_LVC1_SCL")
	)
	(segment
		(start 446.258188 -317.159894)
		(end 446.258188 -316.898528)
		(width 0.127)
		(layer "In2.Cu")
		(net "I3C_SPD_DDREFGH_CPU0_LVC1_SCL")
	)
	(segment
		(start 464.50504 -312.443368)
		(end 465.3661 -311.582308)
		(width 0.127)
		(layer "In2.Cu")
		(net "I3C_SPD_DDREFGH_CPU0_LVC1_SCL")
	)
	(segment
		(start 432.172872 -317.721996)
		(end 433.579524 -317.721996)
		(width 0.127)
		(layer "In2.Cu")
		(net "I3C_SPD_DDREFGH_CPU0_LVC1_SCL")
	)
	(segment
		(start 451.91172 -164.27577)
		(end 451.91172 -150.348188)
		(width 0.127)
		(layer "In2.Cu")
		(net "I3C_SPD_DDREFGH_CPU0_LVC1_SCL")
	)
	(segment
		(start 435.519322 -317.871094)
		(end 437.964072 -317.871094)
		(width 0.127)
		(layer "In2.Cu")
		(net "I3C_SPD_DDREFGH_CPU0_LVC1_SCL")
	)
	(segment
		(start 443.710314 -318.127634)
		(end 445.290448 -318.127634)
		(width 0.127)
		(layer "In2.Cu")
		(net "I3C_SPD_DDREFGH_CPU0_LVC1_SCL")
	)
	(segment
		(start 458.439266 -314.558934)
		(end 459.433422 -313.564778)
		(width 0.127)
		(layer "In2.Cu")
		(net "I3C_SPD_DDREFGH_CPU0_LVC1_SCL")
	)
	(segment
		(start 449.126102 -317.424308)
		(end 450.192394 -317.424308)
		(width 0.127)
		(layer "In2.Cu")
		(net "I3C_SPD_DDREFGH_CPU0_LVC1_SCL")
	)
	(segment
		(start 433.984654 -317.316866)
		(end 434.965094 -317.316866)
		(width 0.127)
		(layer "In2.Cu")
		(net "I3C_SPD_DDREFGH_CPU0_LVC1_SCL")
	)
	(segment
		(start 448.881246 -317.669164)
		(end 449.126102 -317.424308)
		(width 0.127)
		(layer "In2.Cu")
		(net "I3C_SPD_DDREFGH_CPU0_LVC1_SCL")
	)
	(segment
		(start 465.3661 -177.73015)
		(end 451.91172 -164.27577)
		(width 0.127)
		(layer "In2.Cu")
		(net "I3C_SPD_DDREFGH_CPU0_LVC1_SCL")
	)
	(segment
		(start 447.307716 -317.669164)
		(end 448.881246 -317.669164)
		(width 0.127)
		(layer "In2.Cu")
		(net "I3C_SPD_DDREFGH_CPU0_LVC1_SCL")
	)
	(segment
		(start 458.22997 -314.558934)
		(end 458.439266 -314.558934)
		(width 0.127)
		(layer "In2.Cu")
		(net "I3C_SPD_DDREFGH_CPU0_LVC1_SCL")
	)
	(segment
		(start 431.762408 -316.336172)
		(end 431.762408 -317.311532)
		(width 0.127)
		(layer "In2.Cu")
		(net "I3C_SPD_DDREFGH_CPU0_LVC1_SCL")
	)
	(segment
		(start 451.91172 -150.348188)
		(end 451.71614 -150.152608)
		(width 0.127)
		(layer "In2.Cu")
		(net "I3C_SPD_DDREFGH_CPU0_LVC1_SCL")
	)
	(segment
		(start 431.762408 -317.311532)
		(end 432.172872 -317.721996)
		(width 0.127)
		(layer "In2.Cu")
		(net "I3C_SPD_DDREFGH_CPU0_LVC1_SCL")
	)
	(segment
		(start 460.153004 -313.564778)
		(end 460.50962 -313.208162)
		(width 0.127)
		(layer "In2.Cu")
		(net "I3C_SPD_DDREFGH_CPU0_LVC1_SCL")
	)
	(segment
		(start 453.880982 -315.409326)
		(end 454.246742 -315.409326)
		(width 0.127)
		(layer "In2.Cu")
		(net "I3C_SPD_DDREFGH_CPU0_LVC1_SCL")
	)
	(segment
		(start 460.50962 -313.208162)
		(end 461.026002 -313.208162)
		(width 0.127)
		(layer "In2.Cu")
		(net "I3C_SPD_DDREFGH_CPU0_LVC1_SCL")
	)
	(segment
		(start 462.18348 -312.443368)
		(end 464.50504 -312.443368)
		(width 0.127)
		(layer "In2.Cu")
		(net "I3C_SPD_DDREFGH_CPU0_LVC1_SCL")
	)
	(segment
		(start 465.3661 -311.582308)
		(end 465.3661 -177.73015)
		(width 0.127)
		(layer "In2.Cu")
		(net "I3C_SPD_DDREFGH_CPU0_LVC1_SCL")
	)
	(segment
		(start 446.53708 -316.898528)
		(end 447.307716 -317.669164)
		(width 0.127)
		(layer "In2.Cu")
		(net "I3C_SPD_DDREFGH_CPU0_LVC1_SCL")
	)
	(segment
		(start 434.965094 -317.316866)
		(end 435.519322 -317.871094)
		(width 0.127)
		(layer "In2.Cu")
		(net "I3C_SPD_DDREFGH_CPU0_LVC1_SCL")
	)
	(segment
		(start 454.6981 -317.77686)
		(end 456.071478 -317.77686)
		(width 0.127)
		(layer "In2.Cu")
		(net "I3C_SPD_DDREFGH_CPU0_LVC1_SCL")
	)
	(segment
		(start 437.964072 -317.871094)
		(end 438.668414 -317.166752)
		(width 0.127)
		(layer "In2.Cu")
		(net "I3C_SPD_DDREFGH_CPU0_LVC1_SCL")
	)
	(segment
		(start 461.026002 -313.208162)
		(end 461.418686 -313.208162)
		(width 0.127)
		(layer "In2.Cu")
		(net "I3C_SPD_DDREFGH_CPU0_LVC1_SCL")
	)
	(segment
		(start 450.544184 -317.776098)
		(end 451.866 -317.776098)
		(width 0.127)
		(layer "In2.Cu")
		(net "I3C_SPD_DDREFGH_CPU0_LVC1_SCL")
	)
	(segment
		(start 451.71614 -150.152608)
		(end 451.69074 -150.152608)
		(width 0.127)
		(layer "In2.Cu")
		(net "I3C_SPD_DDREFGH_CPU0_LVC1_SCL")
	)
	(segment
		(start 442.196474 -321.400932)
		(end 442.196474 -319.641474)
		(width 0.127)
		(layer "In2.Cu")
		(net "I3C_SPD_DDREFGH_CPU0_LVC1_SCL")
	)
	(segment
		(start 442.196474 -319.641474)
		(end 443.710314 -318.127634)
		(width 0.127)
		(layer "In2.Cu")
		(net "I3C_SPD_DDREFGH_CPU0_LVC1_SCL")
	)
	(segment
		(start 456.254612 -316.534292)
		(end 458.22997 -314.558934)
		(width 0.127)
		(layer "In2.Cu")
		(net "I3C_SPD_DDREFGH_CPU0_LVC1_SCL")
	)
	(segment
		(start 438.97677 -321.528694)
		(end 439.467244 -322.019168)
		(width 0.127)
		(layer "In2.Cu")
		(net "I3C_SPD_DDREFGH_CPU0_LVC1_SCL")
	)
	(segment
		(start 456.071478 -317.77686)
		(end 456.254612 -317.593726)
		(width 0.127)
		(layer "In2.Cu")
		(net "I3C_SPD_DDREFGH_CPU0_LVC1_SCL")
	)
	(segment
		(start 456.254612 -317.593726)
		(end 456.254612 -316.534292)
		(width 0.127)
		(layer "In2.Cu")
		(net "I3C_SPD_DDREFGH_CPU0_LVC1_SCL")
	)
	(segment
		(start 451.866 -317.776098)
		(end 453.145398 -316.4967)
		(width 0.127)
		(layer "In2.Cu")
		(net "I3C_SPD_DDREFGH_CPU0_LVC1_SCL")
	)
	(segment
		(start 438.668414 -317.166752)
		(end 438.668414 -318.544194)
		(width 0.127)
		(layer "In2.Cu")
		(net "I3C_SPD_DDREFGH_CPU0_LVC1_SCL")
	)
	(segment
		(start 438.668414 -318.544194)
		(end 438.97677 -318.85255)
		(width 0.127)
		(layer "In2.Cu")
		(net "I3C_SPD_DDREFGH_CPU0_LVC1_SCL")
	)
	(segment
		(start 433.579524 -317.721996)
		(end 433.984654 -317.316866)
		(width 0.127)
		(layer "In2.Cu")
		(net "I3C_SPD_DDREFGH_CPU0_LVC1_SCL")
	)
	(segment
		(start 453.145398 -316.4967)
		(end 453.145398 -316.14491)
		(width 0.127)
		(layer "In2.Cu")
		(net "I3C_SPD_DDREFGH_CPU0_LVC1_SCL")
	)
	(segment
		(start 441.578238 -322.019168)
		(end 442.196474 -321.400932)
		(width 0.127)
		(layer "In2.Cu")
		(net "I3C_SPD_DDREFGH_CPU0_LVC1_SCL")
	)
	(segment
		(start 454.246742 -315.409326)
		(end 454.246742 -317.325502)
		(width 0.127)
		(layer "In2.Cu")
		(net "I3C_SPD_DDREFGH_CPU0_LVC1_SCL")
	)
	(segment
		(start 454.246742 -317.325502)
		(end 454.6981 -317.77686)
		(width 0.127)
		(layer "In2.Cu")
		(net "I3C_SPD_DDREFGH_CPU0_LVC1_SCL")
	)
	(segment
		(start 438.97677 -318.85255)
		(end 438.97677 -321.528694)
		(width 0.127)
		(layer "In2.Cu")
		(net "I3C_SPD_DDREFGH_CPU0_LVC1_SCL")
	)
	(segment
		(start 309.1942 -151.374348)
		(end 348.9706 -151.374348)
		(width 0.127)
		(layer "In13.Cu")
		(net "I3C_SPD_DDREFGH_CPU0_LVC1_SCL")
	)
	(segment
		(start 308.356 -152.212548)
		(end 309.1942 -151.374348)
		(width 0.127)
		(layer "In13.Cu")
		(net "I3C_SPD_DDREFGH_CPU0_LVC1_SCL")
	)
	(segment
		(start 397.356838 -151.865584)
		(end 402.351494 -146.870928)
		(width 0.127)
		(layer "In13.Cu")
		(net "I3C_SPD_DDREFGH_CPU0_LVC1_SCL")
	)
	(segment
		(start 402.351494 -146.870928)
		(end 425.472352 -146.870928)
		(width 0.127)
		(layer "In13.Cu")
		(net "I3C_SPD_DDREFGH_CPU0_LVC1_SCL")
	)
	(segment
		(start 448.7164 -147.361148)
		(end 451.50786 -150.152608)
		(width 0.127)
		(layer "In13.Cu")
		(net "I3C_SPD_DDREFGH_CPU0_LVC1_SCL")
	)
	(segment
		(start 349.4786 -150.866348)
		(end 389.74268 -150.866348)
		(width 0.127)
		(layer "In13.Cu")
		(net "I3C_SPD_DDREFGH_CPU0_LVC1_SCL")
	)
	(segment
		(start 390.741916 -151.865584)
		(end 397.356838 -151.865584)
		(width 0.127)
		(layer "In13.Cu")
		(net "I3C_SPD_DDREFGH_CPU0_LVC1_SCL")
	)
	(segment
		(start 389.74268 -150.866348)
		(end 390.741916 -151.865584)
		(width 0.127)
		(layer "In13.Cu")
		(net "I3C_SPD_DDREFGH_CPU0_LVC1_SCL")
	)
	(segment
		(start 451.50786 -150.152608)
		(end 451.69074 -150.152608)
		(width 0.127)
		(layer "In13.Cu")
		(net "I3C_SPD_DDREFGH_CPU0_LVC1_SCL")
	)
	(segment
		(start 425.962572 -147.361148)
		(end 448.7164 -147.361148)
		(width 0.127)
		(layer "In13.Cu")
		(net "I3C_SPD_DDREFGH_CPU0_LVC1_SCL")
	)
	(segment
		(start 348.9706 -151.374348)
		(end 349.4786 -150.866348)
		(width 0.127)
		(layer "In13.Cu")
		(net "I3C_SPD_DDREFGH_CPU0_LVC1_SCL")
	)
	(segment
		(start 425.472352 -146.870928)
		(end 425.962572 -147.361148)
		(width 0.127)
		(layer "In13.Cu")
		(net "I3C_SPD_DDREFGH_CPU0_LVC1_SCL")
	)
	(via
		(at 302.99406 -152.474168)
		(size 0.6604)
		(drill 0.3302)
		(layers "F.Cu" "B.Cu")
		(net "I3C_SPD_DDREFGH_CPU0_LVC1_R_SDA")
	)
	(segment
		(start 303.0728 -152.395428)
		(end 302.99406 -152.474168)
		(width 0.12954)
		(layer "B.Cu")
		(net "I3C_SPD_DDREFGH_CPU0_LVC1_R_SDA")
	)
	(segment
		(start 303.86274 -152.395428)
		(end 303.0728 -152.395428)
		(width 0.12954)
		(layer "B.Cu")
		(net "I3C_SPD_DDREFGH_CPU0_LVC1_R_SDA")
	)
	(segment
		(start 305.07305 -152.119584)
		(end 304.138584 -152.119584)
		(width 0.12954)
		(layer "B.Cu")
		(net "I3C_SPD_DDREFGH_CPU0_LVC1_R_SDA")
	)
	(segment
		(start 304.138584 -152.119584)
		(end 303.86274 -152.395428)
		(width 0.12954)
		(layer "B.Cu")
		(net "I3C_SPD_DDREFGH_CPU0_LVC1_R_SDA")
	)
	(segment
		(start 302.99406 -152.474168)
		(end 302.87595 -152.356058)
		(width 0.12954)
		(layer "B.Cu")
		(net "I3C_SPD_DDREFGH_CPU0_LVC1_R_SDA")
	)
	(segment
		(start 305.133248 -152.179782)
		(end 305.07305 -152.119584)
		(width 0.12954)
		(layer "B.Cu")
		(net "I3C_SPD_DDREFGH_CPU0_LVC1_R_SDA")
	)
	(segment
		(start 302.87595 -152.356058)
		(end 301.258732 -152.356058)
		(width 0.12954)
		(layer "B.Cu")
		(net "I3C_SPD_DDREFGH_CPU0_LVC1_R_SDA")
	)
	(via
		(at 304.10912 -155.029408)
		(size 0.6604)
		(drill 0.3302)
		(layers "F.Cu" "B.Cu")
		(net "I3C_SPD_DDREFGH_CPU0_LVC1_R_SCL")
	)
	(segment
		(start 304.138584 -153.901394)
		(end 304.138584 -154.409902)
		(width 0.12954)
		(layer "B.Cu")
		(net "I3C_SPD_DDREFGH_CPU0_LVC1_R_SCL")
	)
	(segment
		(start 305.224688 -153.82367)
		(end 305.146964 -153.901394)
		(width 0.12954)
		(layer "B.Cu")
		(net "I3C_SPD_DDREFGH_CPU0_LVC1_R_SCL")
	)
	(segment
		(start 305.146964 -153.901394)
		(end 304.138584 -153.901394)
		(width 0.12954)
		(layer "B.Cu")
		(net "I3C_SPD_DDREFGH_CPU0_LVC1_R_SCL")
	)
	(segment
		(start 302.763174 -155.029408)
		(end 301.994824 -154.261058)
		(width 0.12954)
		(layer "B.Cu")
		(net "I3C_SPD_DDREFGH_CPU0_LVC1_R_SCL")
	)
	(segment
		(start 304.10912 -154.439366)
		(end 304.10912 -155.029408)
		(width 0.12954)
		(layer "B.Cu")
		(net "I3C_SPD_DDREFGH_CPU0_LVC1_R_SCL")
	)
	(segment
		(start 304.10912 -155.029408)
		(end 302.763174 -155.029408)
		(width 0.12954)
		(layer "B.Cu")
		(net "I3C_SPD_DDREFGH_CPU0_LVC1_R_SCL")
	)
	(segment
		(start 304.138584 -154.409902)
		(end 304.10912 -154.439366)
		(width 0.12954)
		(layer "B.Cu")
		(net "I3C_SPD_DDREFGH_CPU0_LVC1_R_SCL")
	)
	(segment
		(start 301.994824 -154.261058)
		(end 301.258732 -154.261058)
		(width 0.12954)
		(layer "B.Cu")
		(net "I3C_SPD_DDREFGH_CPU0_LVC1_R_SCL")
	)
	(via
		(at 187.34913 -14.714728)
		(size 0.508)
		(drill 0.254)
		(layers "F.Cu" "B.Cu")
		(net "I3C_SPD_DDREFGH_CPU0_BMC_SDA")
	)
	(via
		(at 294.2082 -148.808948)
		(size 0.762)
		(drill 0.254)
		(layers "F.Cu" "B.Cu")
		(net "I3C_SPD_DDREFGH_CPU0_BMC_SDA")
	)
	(segment
		(start 187.34913 -14.00048)
		(end 187.34913 -14.714728)
		(width 0.12954)
		(layer "B.Cu")
		(net "I3C_SPD_DDREFGH_CPU0_BMC_SDA")
	)
	(segment
		(start 297.0784 -149.266148)
		(end 297.948858 -149.266148)
		(width 0.12954)
		(layer "B.Cu")
		(net "I3C_SPD_DDREFGH_CPU0_BMC_SDA")
	)
	(segment
		(start 294.2082 -148.808948)
		(end 296.6212 -148.808948)
		(width 0.12954)
		(layer "B.Cu")
		(net "I3C_SPD_DDREFGH_CPU0_BMC_SDA")
	)
	(segment
		(start 296.6212 -148.808948)
		(end 297.0784 -149.266148)
		(width 0.12954)
		(layer "B.Cu")
		(net "I3C_SPD_DDREFGH_CPU0_BMC_SDA")
	)
	(segment
		(start 300.403768 -151.721058)
		(end 301.258732 -151.721058)
		(width 0.12954)
		(layer "B.Cu")
		(net "I3C_SPD_DDREFGH_CPU0_BMC_SDA")
	)
	(segment
		(start 297.948858 -149.266148)
		(end 300.403768 -151.721058)
		(width 0.12954)
		(layer "B.Cu")
		(net "I3C_SPD_DDREFGH_CPU0_BMC_SDA")
	)
	(segment
		(start 216.401904 -50.572924)
		(end 214.366856 -50.572924)
		(width 0.127)
		(layer "In2.Cu")
		(net "I3C_SPD_DDREFGH_CPU0_BMC_SDA")
	)
	(segment
		(start 294.2082 -148.808948)
		(end 289.55746 -144.158208)
		(width 0.127)
		(layer "In2.Cu")
		(net "I3C_SPD_DDREFGH_CPU0_BMC_SDA")
	)
	(segment
		(start 270.28648 -94.73438)
		(end 265.915648 -90.363548)
		(width 0.127)
		(layer "In2.Cu")
		(net "I3C_SPD_DDREFGH_CPU0_BMC_SDA")
	)
	(segment
		(start 192.585848 -22.855174)
		(end 192.585848 -18.733008)
		(width 0.127)
		(layer "In2.Cu")
		(net "I3C_SPD_DDREFGH_CPU0_BMC_SDA")
	)
	(segment
		(start 278.714708 -144.158208)
		(end 270.28648 -135.72998)
		(width 0.127)
		(layer "In2.Cu")
		(net "I3C_SPD_DDREFGH_CPU0_BMC_SDA")
	)
	(segment
		(start 214.366856 -50.572924)
		(end 193.609722 -29.81579)
		(width 0.127)
		(layer "In2.Cu")
		(net "I3C_SPD_DDREFGH_CPU0_BMC_SDA")
	)
	(segment
		(start 192.276222 -18.423382)
		(end 190.896748 -18.423382)
		(width 0.127)
		(layer "In2.Cu")
		(net "I3C_SPD_DDREFGH_CPU0_BMC_SDA")
	)
	(segment
		(start 187.34913 -14.875764)
		(end 187.34913 -14.714728)
		(width 0.127)
		(layer "In2.Cu")
		(net "I3C_SPD_DDREFGH_CPU0_BMC_SDA")
	)
	(segment
		(start 192.585848 -18.733008)
		(end 192.276222 -18.423382)
		(width 0.127)
		(layer "In2.Cu")
		(net "I3C_SPD_DDREFGH_CPU0_BMC_SDA")
	)
	(segment
		(start 265.915648 -90.363548)
		(end 256.192528 -90.363548)
		(width 0.127)
		(layer "In2.Cu")
		(net "I3C_SPD_DDREFGH_CPU0_BMC_SDA")
	)
	(segment
		(start 193.609722 -29.81579)
		(end 193.609722 -23.879048)
		(width 0.127)
		(layer "In2.Cu")
		(net "I3C_SPD_DDREFGH_CPU0_BMC_SDA")
	)
	(segment
		(start 256.192528 -90.363548)
		(end 216.401904 -50.572924)
		(width 0.127)
		(layer "In2.Cu")
		(net "I3C_SPD_DDREFGH_CPU0_BMC_SDA")
	)
	(segment
		(start 289.55746 -144.158208)
		(end 278.714708 -144.158208)
		(width 0.127)
		(layer "In2.Cu")
		(net "I3C_SPD_DDREFGH_CPU0_BMC_SDA")
	)
	(segment
		(start 190.896748 -18.423382)
		(end 187.34913 -14.875764)
		(width 0.127)
		(layer "In2.Cu")
		(net "I3C_SPD_DDREFGH_CPU0_BMC_SDA")
	)
	(segment
		(start 270.28648 -135.72998)
		(end 270.28648 -94.73438)
		(width 0.127)
		(layer "In2.Cu")
		(net "I3C_SPD_DDREFGH_CPU0_BMC_SDA")
	)
	(segment
		(start 193.609722 -23.879048)
		(end 192.585848 -22.855174)
		(width 0.127)
		(layer "In2.Cu")
		(net "I3C_SPD_DDREFGH_CPU0_BMC_SDA")
	)
	(via
		(at 298.505118 -151.323548)
		(size 0.762)
		(drill 0.254)
		(layers "F.Cu" "B.Cu")
		(net "I3C_SPD_DDREFGH_CPU0_BMC_SCL")
	)
	(via
		(at 188.309758 -14.714728)
		(size 0.508)
		(drill 0.254)
		(layers "F.Cu" "B.Cu")
		(net "I3C_SPD_DDREFGH_CPU0_BMC_SCL")
	)
	(segment
		(start 188.309758 -14.00048)
		(end 188.309758 -14.714728)
		(width 0.12954)
		(layer "B.Cu")
		(net "I3C_SPD_DDREFGH_CPU0_BMC_SCL")
	)
	(segment
		(start 300.10608 -152.36825)
		(end 300.10608 -153.492454)
		(width 0.12954)
		(layer "B.Cu")
		(net "I3C_SPD_DDREFGH_CPU0_BMC_SCL")
	)
	(segment
		(start 299.061378 -151.323548)
		(end 300.10608 -152.36825)
		(width 0.12954)
		(layer "B.Cu")
		(net "I3C_SPD_DDREFGH_CPU0_BMC_SCL")
	)
	(segment
		(start 300.239684 -153.626058)
		(end 301.258732 -153.626058)
		(width 0.12954)
		(layer "B.Cu")
		(net "I3C_SPD_DDREFGH_CPU0_BMC_SCL")
	)
	(segment
		(start 300.10608 -153.492454)
		(end 300.239684 -153.626058)
		(width 0.12954)
		(layer "B.Cu")
		(net "I3C_SPD_DDREFGH_CPU0_BMC_SCL")
	)
	(segment
		(start 298.505118 -151.323548)
		(end 299.061378 -151.323548)
		(width 0.12954)
		(layer "B.Cu")
		(net "I3C_SPD_DDREFGH_CPU0_BMC_SCL")
	)
	(segment
		(start 193.799206 -23.018496)
		(end 193.799206 -21.917406)
		(width 0.127)
		(layer "In2.Cu")
		(net "I3C_SPD_DDREFGH_CPU0_BMC_SCL")
	)
	(segment
		(start 255.901952 -89.174828)
		(end 216.665048 -49.937924)
		(width 0.127)
		(layer "In2.Cu")
		(net "I3C_SPD_DDREFGH_CPU0_BMC_SCL")
	)
	(segment
		(start 192.596262 -17.788382)
		(end 191.25946 -17.788382)
		(width 0.127)
		(layer "In2.Cu")
		(net "I3C_SPD_DDREFGH_CPU0_BMC_SCL")
	)
	(segment
		(start 193.799206 -21.917406)
		(end 194.152012 -21.5646)
		(width 0.127)
		(layer "In2.Cu")
		(net "I3C_SPD_DDREFGH_CPU0_BMC_SCL")
	)
	(segment
		(start 278.977852 -143.523208)
		(end 270.92148 -135.466836)
		(width 0.127)
		(layer "In2.Cu")
		(net "I3C_SPD_DDREFGH_CPU0_BMC_SCL")
	)
	(segment
		(start 290.199572 -143.523208)
		(end 278.977852 -143.523208)
		(width 0.127)
		(layer "In2.Cu")
		(net "I3C_SPD_DDREFGH_CPU0_BMC_SCL")
	)
	(segment
		(start 194.152012 -19.344132)
		(end 192.596262 -17.788382)
		(width 0.127)
		(layer "In2.Cu")
		(net "I3C_SPD_DDREFGH_CPU0_BMC_SCL")
	)
	(segment
		(start 270.92148 -94.471236)
		(end 265.625072 -89.174828)
		(width 0.127)
		(layer "In2.Cu")
		(net "I3C_SPD_DDREFGH_CPU0_BMC_SCL")
	)
	(segment
		(start 194.272154 -23.491444)
		(end 193.799206 -23.018496)
		(width 0.127)
		(layer "In2.Cu")
		(net "I3C_SPD_DDREFGH_CPU0_BMC_SCL")
	)
	(segment
		(start 298.505118 -151.323548)
		(end 297.999912 -151.323548)
		(width 0.127)
		(layer "In2.Cu")
		(net "I3C_SPD_DDREFGH_CPU0_BMC_SCL")
	)
	(segment
		(start 216.665048 -49.937924)
		(end 214.63 -49.937924)
		(width 0.127)
		(layer "In2.Cu")
		(net "I3C_SPD_DDREFGH_CPU0_BMC_SCL")
	)
	(segment
		(start 194.152012 -21.5646)
		(end 194.152012 -19.344132)
		(width 0.127)
		(layer "In2.Cu")
		(net "I3C_SPD_DDREFGH_CPU0_BMC_SCL")
	)
	(segment
		(start 191.25946 -17.788382)
		(end 188.309758 -14.83868)
		(width 0.127)
		(layer "In2.Cu")
		(net "I3C_SPD_DDREFGH_CPU0_BMC_SCL")
	)
	(segment
		(start 270.92148 -135.466836)
		(end 270.92148 -94.471236)
		(width 0.127)
		(layer "In2.Cu")
		(net "I3C_SPD_DDREFGH_CPU0_BMC_SCL")
	)
	(segment
		(start 265.625072 -89.174828)
		(end 255.901952 -89.174828)
		(width 0.127)
		(layer "In2.Cu")
		(net "I3C_SPD_DDREFGH_CPU0_BMC_SCL")
	)
	(segment
		(start 194.272154 -29.580078)
		(end 194.272154 -23.491444)
		(width 0.127)
		(layer "In2.Cu")
		(net "I3C_SPD_DDREFGH_CPU0_BMC_SCL")
	)
	(segment
		(start 297.999912 -151.323548)
		(end 290.199572 -143.523208)
		(width 0.127)
		(layer "In2.Cu")
		(net "I3C_SPD_DDREFGH_CPU0_BMC_SCL")
	)
	(segment
		(start 214.63 -49.937924)
		(end 194.272154 -29.580078)
		(width 0.127)
		(layer "In2.Cu")
		(net "I3C_SPD_DDREFGH_CPU0_BMC_SCL")
	)
	(segment
		(start 188.309758 -14.83868)
		(end 188.309758 -14.714728)
		(width 0.127)
		(layer "In2.Cu")
		(net "I3C_SPD_DDREFGH_CPU0_BMC_SCL")
	)
	(segment
		(start 186.861958 -13.600176)
		(end 186.861958 -12.683998)
		(width 0.12954)
		(layer "F.Cu")
		(net "I3C_SPD_DDREFGH_CPU0_BMC_R_SDA")
	)
	(segment
		(start 186.861704 -11.736324)
		(end 187.10148 -11.496548)
		(width 0.12954)
		(layer "F.Cu")
		(net "I3C_SPD_DDREFGH_CPU0_BMC_R_SDA")
	)
	(segment
		(start 186.861958 -12.683998)
		(end 186.861704 -12.683744)
		(width 0.12954)
		(layer "F.Cu")
		(net "I3C_SPD_DDREFGH_CPU0_BMC_R_SDA")
	)
	(segment
		(start 186.861704 -12.683744)
		(end 186.861704 -11.736324)
		(width 0.12954)
		(layer "F.Cu")
		(net "I3C_SPD_DDREFGH_CPU0_BMC_R_SDA")
	)
	(via
		(at 187.10148 -11.496548)
		(size 0.508)
		(drill 0.254)
		(layers "F.Cu" "B.Cu")
		(net "I3C_SPD_DDREFGH_CPU0_BMC_R_SDA")
	)
	(segment
		(start 187.34913 -11.744198)
		(end 187.34913 -13.20038)
		(width 0.12954)
		(layer "B.Cu")
		(net "I3C_SPD_DDREFGH_CPU0_BMC_R_SDA")
	)
	(segment
		(start 187.10148 -11.496548)
		(end 187.34913 -11.744198)
		(width 0.12954)
		(layer "B.Cu")
		(net "I3C_SPD_DDREFGH_CPU0_BMC_R_SDA")
	)
	(segment
		(start 187.461906 -13.600176)
		(end 187.461906 -12.683998)
		(width 0.12954)
		(layer "F.Cu")
		(net "I3C_SPD_DDREFGH_CPU0_BMC_R_SCL")
	)
	(segment
		(start 187.461652 -12.683744)
		(end 187.461652 -11.847576)
		(width 0.12954)
		(layer "F.Cu")
		(net "I3C_SPD_DDREFGH_CPU0_BMC_R_SCL")
	)
	(segment
		(start 187.461652 -11.847576)
		(end 187.9854 -11.323828)
		(width 0.12954)
		(layer "F.Cu")
		(net "I3C_SPD_DDREFGH_CPU0_BMC_R_SCL")
	)
	(segment
		(start 187.461906 -12.683998)
		(end 187.461652 -12.683744)
		(width 0.12954)
		(layer "F.Cu")
		(net "I3C_SPD_DDREFGH_CPU0_BMC_R_SCL")
	)
	(segment
		(start 187.9854 -11.323828)
		(end 187.9854 -10.455148)
		(width 0.12954)
		(layer "F.Cu")
		(net "I3C_SPD_DDREFGH_CPU0_BMC_R_SCL")
	)
	(via
		(at 187.9854 -10.455148)
		(size 0.508)
		(drill 0.254)
		(layers "F.Cu" "B.Cu")
		(net "I3C_SPD_DDREFGH_CPU0_BMC_R_SCL")
	)
	(segment
		(start 188.06668 -10.536428)
		(end 188.06668 -13.071094)
		(width 0.12954)
		(layer "B.Cu")
		(net "I3C_SPD_DDREFGH_CPU0_BMC_R_SCL")
	)
	(segment
		(start 187.9854 -10.455148)
		(end 188.06668 -10.536428)
		(width 0.12954)
		(layer "B.Cu")
		(net "I3C_SPD_DDREFGH_CPU0_BMC_R_SCL")
	)
	(segment
		(start 188.195966 -13.20038)
		(end 188.309758 -13.20038)
		(width 0.12954)
		(layer "B.Cu")
		(net "I3C_SPD_DDREFGH_CPU0_BMC_R_SCL")
	)
	(segment
		(start 188.06668 -13.071094)
		(end 188.195966 -13.20038)
		(width 0.12954)
		(layer "B.Cu")
		(net "I3C_SPD_DDREFGH_CPU0_BMC_R_SCL")
	)
	(segment
		(start 112.579912 -231.436418)
		(end 112.579912 -230.900732)
		(width 0.12954)
		(layer "F.Cu")
		(net "I3C_SPD_DDRABCD_CPU1_SDA")
	)
	(segment
		(start 112.579912 -230.900732)
		(end 112.580166 -230.900478)
		(width 0.12954)
		(layer "F.Cu")
		(net "I3C_SPD_DDRABCD_CPU1_SDA")
	)
	(via
		(at 112.580166 -230.900478)
		(size 0.4572)
		(drill 0.2032)
		(layers "F.Cu" "B.Cu")
		(net "I3C_SPD_DDRABCD_CPU1_SDA")
	)
	(via
		(at 92.848938 -199.90181)
		(size 0.6604)
		(drill 0.3302)
		(layers "F.Cu" "B.Cu")
		(net "I3C_SPD_DDRABCD_CPU1_SDA")
	)
	(segment
		(start 109.573568 -227.320602)
		(end 109.579664 -227.317046)
		(width 0.0889)
		(layer "B.Cu")
		(net "I3C_SPD_DDRABCD_CPU1_SDA")
	)
	(segment
		(start 86.830662 -216.259156)
		(end 86.830662 -215.677242)
		(width 0.0889)
		(layer "B.Cu")
		(net "I3C_SPD_DDRABCD_CPU1_SDA")
	)
	(segment
		(start 108.163614 -225.527616)
		(end 108.154724 -225.522536)
		(width 0.0889)
		(layer "B.Cu")
		(net "I3C_SPD_DDRABCD_CPU1_SDA")
	)
	(segment
		(start 108.633768 -226.341686)
		(end 108.624878 -226.336606)
		(width 0.0889)
		(layer "B.Cu")
		(net "I3C_SPD_DDRABCD_CPU1_SDA")
	)
	(segment
		(start 92.848938 -199.90181)
		(end 92.848938 -195.32219)
		(width 0.12954)
		(layer "B.Cu")
		(net "I3C_SPD_DDRABCD_CPU1_SDA")
	)
	(segment
		(start 94.209108 -193.96202)
		(end 94.209108 -191.105282)
		(width 0.12954)
		(layer "B.Cu")
		(net "I3C_SPD_DDRABCD_CPU1_SDA")
	)
	(segment
		(start 95.225108 -191.105282)
		(end 94.209108 -191.105282)
		(width 0.12954)
		(layer "B.Cu")
		(net "I3C_SPD_DDRABCD_CPU1_SDA")
	)
	(segment
		(start 107.693968 -224.065084)
		(end 107.700064 -224.061528)
		(width 0.0889)
		(layer "B.Cu")
		(net "I3C_SPD_DDRABCD_CPU1_SDA")
	)
	(segment
		(start 88.240616 -218.692222)
		(end 88.240616 -218.682316)
		(width 0.0889)
		(layer "B.Cu")
		(net "I3C_SPD_DDRABCD_CPU1_SDA")
	)
	(segment
		(start 109.579664 -226.345242)
		(end 109.573568 -226.341686)
		(width 0.0889)
		(layer "B.Cu")
		(net "I3C_SPD_DDRABCD_CPU1_SDA")
	)
	(segment
		(start 92.106496 -219.82176)
		(end 92.091764 -219.830396)
		(width 0.0889)
		(layer "B.Cu")
		(net "I3C_SPD_DDRABCD_CPU1_SDA")
	)
	(segment
		(start 93.470984 -202.531218)
		(end 92.848938 -201.909172)
		(width 0.12954)
		(layer "B.Cu")
		(net "I3C_SPD_DDRABCD_CPU1_SDA")
	)
	(segment
		(start 92.848938 -195.32219)
		(end 94.209108 -193.96202)
		(width 0.12954)
		(layer "B.Cu")
		(net "I3C_SPD_DDRABCD_CPU1_SDA")
	)
	(segment
		(start 90.890598 -210.646518)
		(end 93.470984 -208.066132)
		(width 0.12954)
		(layer "B.Cu")
		(net "I3C_SPD_DDRABCD_CPU1_SDA")
	)
	(segment
		(start 109.573568 -227.969318)
		(end 109.564678 -227.964238)
		(width 0.0889)
		(layer "B.Cu")
		(net "I3C_SPD_DDRABCD_CPU1_SDA")
	)
	(segment
		(start 101.504496 -219.82176)
		(end 101.489764 -219.830396)
		(width 0.0889)
		(layer "B.Cu")
		(net "I3C_SPD_DDRABCD_CPU1_SDA")
	)
	(segment
		(start 95.865696 -219.82176)
		(end 95.850964 -219.830396)
		(width 0.0889)
		(layer "B.Cu")
		(net "I3C_SPD_DDRABCD_CPU1_SDA")
	)
	(segment
		(start 87.958168 -218.202764)
		(end 87.943182 -218.194128)
		(width 0.0889)
		(layer "B.Cu")
		(net "I3C_SPD_DDRABCD_CPU1_SDA")
	)
	(segment
		(start 109.022896 -226.33305)
		(end 109.008164 -226.341686)
		(width 0.0889)
		(layer "B.Cu")
		(net "I3C_SPD_DDRABCD_CPU1_SDA")
	)
	(segment
		(start 87.023956 -216.578434)
		(end 87.01786 -216.574878)
		(width 0.0889)
		(layer "B.Cu")
		(net "I3C_SPD_DDRABCD_CPU1_SDA")
	)
	(segment
		(start 110.513368 -229.597204)
		(end 110.504478 -229.592124)
		(width 0.0889)
		(layer "B.Cu")
		(net "I3C_SPD_DDRABCD_CPU1_SDA")
	)
	(segment
		(start 86.467442 -215.314022)
		(end 86.467442 -214.677752)
		(width 0.12954)
		(layer "B.Cu")
		(net "I3C_SPD_DDRABCD_CPU1_SDA")
	)
	(segment
		(start 107.976416 -223.575626)
		(end 107.976416 -223.561402)
		(width 0.0889)
		(layer "B.Cu")
		(net "I3C_SPD_DDRABCD_CPU1_SDA")
	)
	(segment
		(start 103.384096 -219.82176)
		(end 103.369364 -219.830396)
		(width 0.0889)
		(layer "B.Cu")
		(net "I3C_SPD_DDRABCD_CPU1_SDA")
	)
	(segment
		(start 87.770462 -217.878406)
		(end 87.770462 -217.864182)
		(width 0.0889)
		(layer "B.Cu")
		(net "I3C_SPD_DDRABCD_CPU1_SDA")
	)
	(segment
		(start 110.043214 -228.783388)
		(end 110.034324 -228.778308)
		(width 0.0889)
		(layer "B.Cu")
		(net "I3C_SPD_DDRABCD_CPU1_SDA")
	)
	(segment
		(start 92.848938 -201.909172)
		(end 92.848938 -199.90181)
		(width 0.12954)
		(layer "B.Cu")
		(net "I3C_SPD_DDRABCD_CPU1_SDA")
	)
	(segment
		(start 111.71555 -230.513128)
		(end 111.233204 -230.513128)
		(width 0.0889)
		(layer "B.Cu")
		(net "I3C_SPD_DDRABCD_CPU1_SDA")
	)
	(segment
		(start 90.226896 -219.82176)
		(end 90.212164 -219.830396)
		(width 0.0889)
		(layer "B.Cu")
		(net "I3C_SPD_DDRABCD_CPU1_SDA")
	)
	(segment
		(start 107.693968 -224.7138)
		(end 107.685078 -224.70872)
		(width 0.0889)
		(layer "B.Cu")
		(net "I3C_SPD_DDRABCD_CPU1_SDA")
	)
	(segment
		(start 107.22991 -222.275654)
		(end 107.223814 -222.272098)
		(width 0.0889)
		(layer "B.Cu")
		(net "I3C_SPD_DDRABCD_CPU1_SDA")
	)
	(segment
		(start 106.284014 -222.272098)
		(end 106.275124 -222.267018)
		(width 0.0889)
		(layer "B.Cu")
		(net "I3C_SPD_DDRABCD_CPU1_SDA")
	)
	(segment
		(start 112.049052 -230.680514)
		(end 111.999268 -230.63073)
		(width 0.0889)
		(layer "B.Cu")
		(net "I3C_SPD_DDRABCD_CPU1_SDA")
	)
	(segment
		(start 107.223814 -222.272098)
		(end 107.209082 -222.263462)
		(width 0.0889)
		(layer "B.Cu")
		(net "I3C_SPD_DDRABCD_CPU1_SDA")
	)
	(segment
		(start 103.940864 -219.833952)
		(end 103.934768 -219.830396)
		(width 0.0889)
		(layer "B.Cu")
		(net "I3C_SPD_DDRABCD_CPU1_SDA")
	)
	(segment
		(start 106.096562 -221.94774)
		(end 106.096562 -221.932246)
		(width 0.0889)
		(layer "B.Cu")
		(net "I3C_SPD_DDRABCD_CPU1_SDA")
	)
	(segment
		(start 105.814368 -221.458282)
		(end 105.805478 -221.453202)
		(width 0.0889)
		(layer "B.Cu")
		(net "I3C_SPD_DDRABCD_CPU1_SDA")
	)
	(segment
		(start 93.470984 -208.066132)
		(end 93.470984 -202.531218)
		(width 0.12954)
		(layer "B.Cu")
		(net "I3C_SPD_DDRABCD_CPU1_SDA")
	)
	(segment
		(start 87.488014 -217.388694)
		(end 87.479124 -217.383614)
		(width 0.0889)
		(layer "B.Cu")
		(net "I3C_SPD_DDRABCD_CPU1_SDA")
	)
	(segment
		(start 107.685078 -224.070164)
		(end 107.693968 -224.065084)
		(width 0.0889)
		(layer "B.Cu")
		(net "I3C_SPD_DDRABCD_CPU1_SDA")
	)
	(segment
		(start 107.693968 -223.085914)
		(end 107.685078 -223.080834)
		(width 0.0889)
		(layer "B.Cu")
		(net "I3C_SPD_DDRABCD_CPU1_SDA")
	)
	(segment
		(start 109.855762 -228.45903)
		(end 109.855762 -228.436932)
		(width 0.0889)
		(layer "B.Cu")
		(net "I3C_SPD_DDRABCD_CPU1_SDA")
	)
	(segment
		(start 109.564678 -227.325682)
		(end 109.573568 -227.320602)
		(width 0.0889)
		(layer "B.Cu")
		(net "I3C_SPD_DDRABCD_CPU1_SDA")
	)
	(segment
		(start 107.976162 -225.203258)
		(end 107.976162 -225.187764)
		(width 0.0889)
		(layer "B.Cu")
		(net "I3C_SPD_DDRABCD_CPU1_SDA")
	)
	(segment
		(start 86.830662 -215.677242)
		(end 86.467442 -215.314022)
		(width 0.0889)
		(layer "B.Cu")
		(net "I3C_SPD_DDRABCD_CPU1_SDA")
	)
	(segment
		(start 86.467442 -214.677752)
		(end 90.498676 -210.646518)
		(width 0.12954)
		(layer "B.Cu")
		(net "I3C_SPD_DDRABCD_CPU1_SDA")
	)
	(segment
		(start 105.344214 -220.644212)
		(end 105.3338 -220.638116)
		(width 0.0889)
		(layer "B.Cu")
		(net "I3C_SPD_DDRABCD_CPU1_SDA")
	)
	(segment
		(start 110.519464 -229.60076)
		(end 110.513368 -229.597204)
		(width 0.0889)
		(layer "B.Cu")
		(net "I3C_SPD_DDRABCD_CPU1_SDA")
	)
	(segment
		(start 105.626916 -221.133924)
		(end 105.626916 -221.1197)
		(width 0.0889)
		(layer "B.Cu")
		(net "I3C_SPD_DDRABCD_CPU1_SDA")
	)
	(segment
		(start 111.076994 -230.468932)
		(end 110.974378 -230.40594)
		(width 0.0889)
		(layer "B.Cu")
		(net "I3C_SPD_DDRABCD_CPU1_SDA")
	)
	(segment
		(start 110.04931 -228.786944)
		(end 110.043214 -228.783388)
		(width 0.0889)
		(layer "B.Cu")
		(net "I3C_SPD_DDRABCD_CPU1_SDA")
	)
	(segment
		(start 90.498676 -210.646518)
		(end 90.890598 -210.646518)
		(width 0.12954)
		(layer "B.Cu")
		(net "I3C_SPD_DDRABCD_CPU1_SDA")
	)
	(segment
		(start 104.404668 -220.644212)
		(end 104.395778 -220.639132)
		(width 0.0889)
		(layer "B.Cu")
		(net "I3C_SPD_DDRABCD_CPU1_SDA")
	)
	(segment
		(start 88.710516 -219.506038)
		(end 88.710516 -219.496132)
		(width 0.0889)
		(layer "B.Cu")
		(net "I3C_SPD_DDRABCD_CPU1_SDA")
	)
	(segment
		(start 97.745296 -219.82176)
		(end 97.730564 -219.830396)
		(width 0.0889)
		(layer "B.Cu")
		(net "I3C_SPD_DDRABCD_CPU1_SDA")
	)
	(segment
		(start 93.986096 -219.82176)
		(end 93.971364 -219.830396)
		(width 0.0889)
		(layer "B.Cu")
		(net "I3C_SPD_DDRABCD_CPU1_SDA")
	)
	(segment
		(start 99.624896 -219.82176)
		(end 99.610164 -219.830396)
		(width 0.0889)
		(layer "B.Cu")
		(net "I3C_SPD_DDRABCD_CPU1_SDA")
	)
	(segment
		(start 88.897968 -219.830396)
		(end 88.889078 -219.825316)
		(width 0.0889)
		(layer "B.Cu")
		(net "I3C_SPD_DDRABCD_CPU1_SDA")
	)
	(segment
		(start 108.446316 -226.017328)
		(end 108.446316 -226.003104)
		(width 0.0889)
		(layer "B.Cu")
		(net "I3C_SPD_DDRABCD_CPU1_SDA")
	)
	(segment
		(start 88.428068 -219.01658)
		(end 88.419178 -219.0115)
		(width 0.0889)
		(layer "B.Cu")
		(net "I3C_SPD_DDRABCD_CPU1_SDA")
	)
	(arc
		(start 109.008164 -226.341686)
		(mid 108.820966 -226.391829)
		(end 108.633768 -226.341686)
		(width 0.0889)
		(layer "B.Cu")
		(net "I3C_SPD_DDRABCD_CPU1_SDA")
	)
	(arc
		(start 87.770462 -217.864182)
		(mid 87.691321 -217.589559)
		(end 87.488014 -217.388694)
		(width 0.0889)
		(layer "B.Cu")
		(net "I3C_SPD_DDRABCD_CPU1_SDA")
	)
	(arc
		(start 93.971364 -219.830396)
		(mid 93.784166 -219.880539)
		(end 93.596968 -219.830396)
		(width 0.0889)
		(layer "B.Cu")
		(net "I3C_SPD_DDRABCD_CPU1_SDA")
	)
	(arc
		(start 107.976416 -223.561402)
		(mid 107.897275 -223.286779)
		(end 107.693968 -223.085914)
		(width 0.0889)
		(layer "B.Cu")
		(net "I3C_SPD_DDRABCD_CPU1_SDA")
	)
	(arc
		(start 101.115368 -219.830396)
		(mid 100.832666 -219.75462)
		(end 100.549964 -219.830396)
		(width 0.0889)
		(layer "B.Cu")
		(net "I3C_SPD_DDRABCD_CPU1_SDA")
	)
	(arc
		(start 101.489764 -219.830396)
		(mid 101.302566 -219.880539)
		(end 101.115368 -219.830396)
		(width 0.0889)
		(layer "B.Cu")
		(net "I3C_SPD_DDRABCD_CPU1_SDA")
	)
	(arc
		(start 109.855762 -228.436932)
		(mid 109.774851 -228.166804)
		(end 109.573568 -227.969318)
		(width 0.0889)
		(layer "B.Cu")
		(net "I3C_SPD_DDRABCD_CPU1_SDA")
	)
	(arc
		(start 99.610164 -219.830396)
		(mid 99.422966 -219.880539)
		(end 99.235768 -219.830396)
		(width 0.0889)
		(layer "B.Cu")
		(net "I3C_SPD_DDRABCD_CPU1_SDA")
	)
	(arc
		(start 91.717368 -219.830396)
		(mid 91.434666 -219.75462)
		(end 91.151964 -219.830396)
		(width 0.0889)
		(layer "B.Cu")
		(net "I3C_SPD_DDRABCD_CPU1_SDA")
	)
	(arc
		(start 98.670364 -219.830396)
		(mid 98.483166 -219.880539)
		(end 98.295968 -219.830396)
		(width 0.0889)
		(layer "B.Cu")
		(net "I3C_SPD_DDRABCD_CPU1_SDA")
	)
	(arc
		(start 90.212164 -219.830396)
		(mid 90.024966 -219.880539)
		(end 89.837768 -219.830396)
		(width 0.0889)
		(layer "B.Cu")
		(net "I3C_SPD_DDRABCD_CPU1_SDA")
	)
	(arc
		(start 93.031564 -219.830396)
		(mid 92.844366 -219.880539)
		(end 92.657168 -219.830396)
		(width 0.0889)
		(layer "B.Cu")
		(net "I3C_SPD_DDRABCD_CPU1_SDA")
	)
	(arc
		(start 99.235768 -219.830396)
		(mid 98.953066 -219.75462)
		(end 98.670364 -219.830396)
		(width 0.0889)
		(layer "B.Cu")
		(net "I3C_SPD_DDRABCD_CPU1_SDA")
	)
	(arc
		(start 110.034324 -228.778308)
		(mid 109.90341 -228.641948)
		(end 109.855762 -228.45903)
		(width 0.0889)
		(layer "B.Cu")
		(net "I3C_SPD_DDRABCD_CPU1_SDA")
	)
	(arc
		(start 94.536768 -219.830396)
		(mid 94.262569 -219.754561)
		(end 93.986096 -219.82176)
		(width 0.0889)
		(layer "B.Cu")
		(net "I3C_SPD_DDRABCD_CPU1_SDA")
	)
	(arc
		(start 102.055168 -219.830396)
		(mid 101.780969 -219.754561)
		(end 101.504496 -219.82176)
		(width 0.0889)
		(layer "B.Cu")
		(net "I3C_SPD_DDRABCD_CPU1_SDA")
	)
	(arc
		(start 95.476568 -219.830396)
		(mid 95.193866 -219.75462)
		(end 94.911164 -219.830396)
		(width 0.0889)
		(layer "B.Cu")
		(net "I3C_SPD_DDRABCD_CPU1_SDA")
	)
	(arc
		(start 97.356168 -219.830396)
		(mid 97.073466 -219.75462)
		(end 96.790764 -219.830396)
		(width 0.0889)
		(layer "B.Cu")
		(net "I3C_SPD_DDRABCD_CPU1_SDA")
	)
	(arc
		(start 107.976162 -225.187764)
		(mid 107.896792 -224.91403)
		(end 107.693968 -224.7138)
		(width 0.0889)
		(layer "B.Cu")
		(net "I3C_SPD_DDRABCD_CPU1_SDA")
	)
	(arc
		(start 111.233204 -230.513128)
		(mid 111.152027 -230.501876)
		(end 111.076994 -230.468932)
		(width 0.0889)
		(layer "B.Cu")
		(net "I3C_SPD_DDRABCD_CPU1_SDA")
	)
	(arc
		(start 102.994968 -219.830396)
		(mid 102.712266 -219.75462)
		(end 102.429564 -219.830396)
		(width 0.0889)
		(layer "B.Cu")
		(net "I3C_SPD_DDRABCD_CPU1_SDA")
	)
	(arc
		(start 97.730564 -219.830396)
		(mid 97.543366 -219.880539)
		(end 97.356168 -219.830396)
		(width 0.0889)
		(layer "B.Cu")
		(net "I3C_SPD_DDRABCD_CPU1_SDA")
	)
	(arc
		(start 92.091764 -219.830396)
		(mid 91.904566 -219.880539)
		(end 91.717368 -219.830396)
		(width 0.0889)
		(layer "B.Cu")
		(net "I3C_SPD_DDRABCD_CPU1_SDA")
	)
	(arc
		(start 106.65841 -222.272098)
		(mid 106.471212 -222.322241)
		(end 106.284014 -222.272098)
		(width 0.0889)
		(layer "B.Cu")
		(net "I3C_SPD_DDRABCD_CPU1_SDA")
	)
	(arc
		(start 96.790764 -219.830396)
		(mid 96.603566 -219.880539)
		(end 96.416368 -219.830396)
		(width 0.0889)
		(layer "B.Cu")
		(net "I3C_SPD_DDRABCD_CPU1_SDA")
	)
	(arc
		(start 107.209082 -222.263462)
		(mid 106.932607 -222.196142)
		(end 106.65841 -222.272098)
		(width 0.0889)
		(layer "B.Cu")
		(net "I3C_SPD_DDRABCD_CPU1_SDA")
	)
	(arc
		(start 105.626916 -221.1197)
		(mid 105.547697 -220.845015)
		(end 105.344214 -220.644212)
		(width 0.0889)
		(layer "B.Cu")
		(net "I3C_SPD_DDRABCD_CPU1_SDA")
	)
	(arc
		(start 110.504478 -229.592124)
		(mid 110.373564 -229.455764)
		(end 110.325916 -229.272846)
		(width 0.0889)
		(layer "B.Cu")
		(net "I3C_SPD_DDRABCD_CPU1_SDA")
	)
	(arc
		(start 90.777568 -219.830396)
		(mid 90.503369 -219.754561)
		(end 90.226896 -219.82176)
		(width 0.0889)
		(layer "B.Cu")
		(net "I3C_SPD_DDRABCD_CPU1_SDA")
	)
	(arc
		(start 87.300562 -217.064336)
		(mid 87.226571 -216.78477)
		(end 87.023956 -216.578434)
		(width 0.0889)
		(layer "B.Cu")
		(net "I3C_SPD_DDRABCD_CPU1_SDA")
	)
	(arc
		(start 87.943182 -218.194128)
		(mid 87.816459 -218.058347)
		(end 87.770462 -217.878406)
		(width 0.0889)
		(layer "B.Cu")
		(net "I3C_SPD_DDRABCD_CPU1_SDA")
	)
	(arc
		(start 109.564678 -227.964238)
		(mid 109.386081 -227.64496)
		(end 109.564678 -227.325682)
		(width 0.0889)
		(layer "B.Cu")
		(net "I3C_SPD_DDRABCD_CPU1_SDA")
	)
	(arc
		(start 105.805478 -221.453202)
		(mid 105.674564 -221.316842)
		(end 105.626916 -221.133924)
		(width 0.0889)
		(layer "B.Cu")
		(net "I3C_SPD_DDRABCD_CPU1_SDA")
	)
	(arc
		(start 93.596968 -219.830396)
		(mid 93.314266 -219.75462)
		(end 93.031564 -219.830396)
		(width 0.0889)
		(layer "B.Cu")
		(net "I3C_SPD_DDRABCD_CPU1_SDA")
	)
	(arc
		(start 110.325916 -229.272846)
		(mid 110.251925 -228.99328)
		(end 110.04931 -228.786944)
		(width 0.0889)
		(layer "B.Cu")
		(net "I3C_SPD_DDRABCD_CPU1_SDA")
	)
	(arc
		(start 108.624878 -226.336606)
		(mid 108.493964 -226.200246)
		(end 108.446316 -226.017328)
		(width 0.0889)
		(layer "B.Cu")
		(net "I3C_SPD_DDRABCD_CPU1_SDA")
	)
	(arc
		(start 100.549964 -219.830396)
		(mid 100.362766 -219.880539)
		(end 100.175568 -219.830396)
		(width 0.0889)
		(layer "B.Cu")
		(net "I3C_SPD_DDRABCD_CPU1_SDA")
	)
	(arc
		(start 88.710516 -219.496132)
		(mid 88.632405 -219.219183)
		(end 88.428068 -219.01658)
		(width 0.0889)
		(layer "B.Cu")
		(net "I3C_SPD_DDRABCD_CPU1_SDA")
	)
	(arc
		(start 106.275124 -222.267018)
		(mid 106.14421 -222.130658)
		(end 106.096562 -221.94774)
		(width 0.0889)
		(layer "B.Cu")
		(net "I3C_SPD_DDRABCD_CPU1_SDA")
	)
	(arc
		(start 103.369364 -219.830396)
		(mid 103.182166 -219.880539)
		(end 102.994968 -219.830396)
		(width 0.0889)
		(layer "B.Cu")
		(net "I3C_SPD_DDRABCD_CPU1_SDA")
	)
	(arc
		(start 106.096562 -221.932246)
		(mid 106.017192 -221.658512)
		(end 105.814368 -221.458282)
		(width 0.0889)
		(layer "B.Cu")
		(net "I3C_SPD_DDRABCD_CPU1_SDA")
	)
	(arc
		(start 112.580166 -230.900478)
		(mid 112.292741 -230.843306)
		(end 112.049052 -230.680514)
		(width 0.0889)
		(layer "B.Cu")
		(net "I3C_SPD_DDRABCD_CPU1_SDA")
	)
	(arc
		(start 87.01786 -216.574878)
		(mid 86.882927 -216.441524)
		(end 86.830662 -216.259156)
		(width 0.0889)
		(layer "B.Cu")
		(net "I3C_SPD_DDRABCD_CPU1_SDA")
	)
	(arc
		(start 92.657168 -219.830396)
		(mid 92.382969 -219.754561)
		(end 92.106496 -219.82176)
		(width 0.0889)
		(layer "B.Cu")
		(net "I3C_SPD_DDRABCD_CPU1_SDA")
	)
	(arc
		(start 108.446316 -226.003104)
		(mid 108.367097 -225.728419)
		(end 108.163614 -225.527616)
		(width 0.0889)
		(layer "B.Cu")
		(net "I3C_SPD_DDRABCD_CPU1_SDA")
	)
	(arc
		(start 107.506516 -222.761556)
		(mid 107.432525 -222.48199)
		(end 107.22991 -222.275654)
		(width 0.0889)
		(layer "B.Cu")
		(net "I3C_SPD_DDRABCD_CPU1_SDA")
	)
	(arc
		(start 110.974378 -230.40594)
		(mid 110.843464 -230.26958)
		(end 110.795816 -230.086662)
		(width 0.0889)
		(layer "B.Cu")
		(net "I3C_SPD_DDRABCD_CPU1_SDA")
	)
	(arc
		(start 107.685078 -223.080834)
		(mid 107.554164 -222.944474)
		(end 107.506516 -222.761556)
		(width 0.0889)
		(layer "B.Cu")
		(net "I3C_SPD_DDRABCD_CPU1_SDA")
	)
	(arc
		(start 88.889078 -219.825316)
		(mid 88.758164 -219.688956)
		(end 88.710516 -219.506038)
		(width 0.0889)
		(layer "B.Cu")
		(net "I3C_SPD_DDRABCD_CPU1_SDA")
	)
	(arc
		(start 95.850964 -219.830396)
		(mid 95.663766 -219.880539)
		(end 95.476568 -219.830396)
		(width 0.0889)
		(layer "B.Cu")
		(net "I3C_SPD_DDRABCD_CPU1_SDA")
	)
	(arc
		(start 111.999268 -230.63073)
		(mid 111.869111 -230.543699)
		(end 111.71555 -230.513128)
		(width 0.0889)
		(layer "B.Cu")
		(net "I3C_SPD_DDRABCD_CPU1_SDA")
	)
	(arc
		(start 107.685078 -224.70872)
		(mid 107.506481 -224.389442)
		(end 107.685078 -224.070164)
		(width 0.0889)
		(layer "B.Cu")
		(net "I3C_SPD_DDRABCD_CPU1_SDA")
	)
	(arc
		(start 109.579664 -227.317046)
		(mid 109.85599 -226.831144)
		(end 109.579664 -226.345242)
		(width 0.0889)
		(layer "B.Cu")
		(net "I3C_SPD_DDRABCD_CPU1_SDA")
	)
	(arc
		(start 87.479124 -217.383614)
		(mid 87.34821 -217.247254)
		(end 87.300562 -217.064336)
		(width 0.0889)
		(layer "B.Cu")
		(net "I3C_SPD_DDRABCD_CPU1_SDA")
	)
	(arc
		(start 109.573568 -226.341686)
		(mid 109.299369 -226.265851)
		(end 109.022896 -226.33305)
		(width 0.0889)
		(layer "B.Cu")
		(net "I3C_SPD_DDRABCD_CPU1_SDA")
	)
	(arc
		(start 110.795816 -230.086662)
		(mid 110.7219 -229.80716)
		(end 110.519464 -229.60076)
		(width 0.0889)
		(layer "B.Cu")
		(net "I3C_SPD_DDRABCD_CPU1_SDA")
	)
	(arc
		(start 102.429564 -219.830396)
		(mid 102.242366 -219.880539)
		(end 102.055168 -219.830396)
		(width 0.0889)
		(layer "B.Cu")
		(net "I3C_SPD_DDRABCD_CPU1_SDA")
	)
	(arc
		(start 100.175568 -219.830396)
		(mid 99.901369 -219.754561)
		(end 99.624896 -219.82176)
		(width 0.0889)
		(layer "B.Cu")
		(net "I3C_SPD_DDRABCD_CPU1_SDA")
	)
	(arc
		(start 88.419178 -219.0115)
		(mid 88.288264 -218.87514)
		(end 88.240616 -218.692222)
		(width 0.0889)
		(layer "B.Cu")
		(net "I3C_SPD_DDRABCD_CPU1_SDA")
	)
	(arc
		(start 88.240616 -218.682316)
		(mid 88.162505 -218.405367)
		(end 87.958168 -218.202764)
		(width 0.0889)
		(layer "B.Cu")
		(net "I3C_SPD_DDRABCD_CPU1_SDA")
	)
	(arc
		(start 104.395778 -220.639132)
		(mid 104.264864 -220.502772)
		(end 104.217216 -220.319854)
		(width 0.0889)
		(layer "B.Cu")
		(net "I3C_SPD_DDRABCD_CPU1_SDA")
	)
	(arc
		(start 91.151964 -219.830396)
		(mid 90.964766 -219.880539)
		(end 90.777568 -219.830396)
		(width 0.0889)
		(layer "B.Cu")
		(net "I3C_SPD_DDRABCD_CPU1_SDA")
	)
	(arc
		(start 96.416368 -219.830396)
		(mid 96.142169 -219.754561)
		(end 95.865696 -219.82176)
		(width 0.0889)
		(layer "B.Cu")
		(net "I3C_SPD_DDRABCD_CPU1_SDA")
	)
	(arc
		(start 108.154724 -225.522536)
		(mid 108.02381 -225.386176)
		(end 107.976162 -225.203258)
		(width 0.0889)
		(layer "B.Cu")
		(net "I3C_SPD_DDRABCD_CPU1_SDA")
	)
	(arc
		(start 89.272364 -219.830396)
		(mid 89.085166 -219.880539)
		(end 88.897968 -219.830396)
		(width 0.0889)
		(layer "B.Cu")
		(net "I3C_SPD_DDRABCD_CPU1_SDA")
	)
	(arc
		(start 89.837768 -219.830396)
		(mid 89.555066 -219.75462)
		(end 89.272364 -219.830396)
		(width 0.0889)
		(layer "B.Cu")
		(net "I3C_SPD_DDRABCD_CPU1_SDA")
	)
	(arc
		(start 103.934768 -219.830396)
		(mid 103.660569 -219.754561)
		(end 103.384096 -219.82176)
		(width 0.0889)
		(layer "B.Cu")
		(net "I3C_SPD_DDRABCD_CPU1_SDA")
	)
	(arc
		(start 98.295968 -219.830396)
		(mid 98.021769 -219.754561)
		(end 97.745296 -219.82176)
		(width 0.0889)
		(layer "B.Cu")
		(net "I3C_SPD_DDRABCD_CPU1_SDA")
	)
	(arc
		(start 107.700064 -224.061528)
		(mid 107.902477 -223.855115)
		(end 107.976416 -223.575626)
		(width 0.0889)
		(layer "B.Cu")
		(net "I3C_SPD_DDRABCD_CPU1_SDA")
	)
	(arc
		(start 104.217216 -220.319854)
		(mid 104.1433 -220.040352)
		(end 103.940864 -219.833952)
		(width 0.0889)
		(layer "B.Cu")
		(net "I3C_SPD_DDRABCD_CPU1_SDA")
	)
	(arc
		(start 94.911164 -219.830396)
		(mid 94.723966 -219.880539)
		(end 94.536768 -219.830396)
		(width 0.0889)
		(layer "B.Cu")
		(net "I3C_SPD_DDRABCD_CPU1_SDA")
	)
	(arc
		(start 105.3338 -220.638116)
		(mid 105.055622 -220.568424)
		(end 104.779064 -220.644212)
		(width 0.0889)
		(layer "B.Cu")
		(net "I3C_SPD_DDRABCD_CPU1_SDA")
	)
	(arc
		(start 104.779064 -220.644212)
		(mid 104.591866 -220.694355)
		(end 104.404668 -220.644212)
		(width 0.0889)
		(layer "B.Cu")
		(net "I3C_SPD_DDRABCD_CPU1_SDA")
	)
	(segment
		(start 110.700566 -230.900478)
		(end 110.700566 -231.436418)
		(width 0.12954)
		(layer "F.Cu")
		(net "I3C_SPD_DDRABCD_CPU1_SCL")
	)
	(via
		(at 92.293186 -202.489816)
		(size 0.6604)
		(drill 0.3302)
		(layers "F.Cu" "B.Cu")
		(net "I3C_SPD_DDRABCD_CPU1_SCL")
	)
	(via
		(at 110.700566 -230.900478)
		(size 0.4572)
		(drill 0.2032)
		(layers "F.Cu" "B.Cu")
		(net "I3C_SPD_DDRABCD_CPU1_SCL")
	)
	(segment
		(start 106.203496 -222.445834)
		(end 106.188764 -222.437198)
		(width 0.0889)
		(layer "B.Cu")
		(net "I3C_SPD_DDRABCD_CPU1_SCL")
	)
	(segment
		(start 109.4867 -226.511866)
		(end 109.47781 -226.506786)
		(width 0.0889)
		(layer "B.Cu")
		(net "I3C_SPD_DDRABCD_CPU1_SCL")
	)
	(segment
		(start 90.614754 -209.96529)
		(end 92.804488 -207.775556)
		(width 0.12954)
		(layer "B.Cu")
		(net "I3C_SPD_DDRABCD_CPU1_SCL")
	)
	(segment
		(start 104.026462 -220.327474)
		(end 104.026462 -220.319854)
		(width 0.0889)
		(layer "B.Cu")
		(net "I3C_SPD_DDRABCD_CPU1_SCL")
	)
	(segment
		(start 105.257854 -220.814646)
		(end 105.248964 -220.809566)
		(width 0.0889)
		(layer "B.Cu")
		(net "I3C_SPD_DDRABCD_CPU1_SCL")
	)
	(segment
		(start 105.436416 -221.149418)
		(end 105.436416 -221.133924)
		(width 0.0889)
		(layer "B.Cu")
		(net "I3C_SPD_DDRABCD_CPU1_SCL")
	)
	(segment
		(start 110.700566 -230.900478)
		(end 110.617762 -230.20528)
		(width 0.0889)
		(layer "B.Cu")
		(net "I3C_SPD_DDRABCD_CPU1_SCL")
	)
	(segment
		(start 109.4867 -228.139752)
		(end 109.47781 -228.134672)
		(width 0.0889)
		(layer "B.Cu")
		(net "I3C_SPD_DDRABCD_CPU1_SCL")
	)
	(segment
		(start 87.110062 -217.086434)
		(end 87.110062 -217.064336)
		(width 0.0889)
		(layer "B.Cu")
		(net "I3C_SPD_DDRABCD_CPU1_SCL")
	)
	(segment
		(start 98.765868 -219.995496)
		(end 98.755454 -220.001592)
		(width 0.0889)
		(layer "B.Cu")
		(net "I3C_SPD_DDRABCD_CPU1_SCL")
	)
	(segment
		(start 110.423198 -229.765606)
		(end 110.41761 -229.762304)
		(width 0.0889)
		(layer "B.Cu")
		(net "I3C_SPD_DDRABCD_CPU1_SCL")
	)
	(segment
		(start 92.293186 -202.489816)
		(end 91.939618 -202.136248)
		(width 0.12954)
		(layer "B.Cu")
		(net "I3C_SPD_DDRABCD_CPU1_SCL")
	)
	(segment
		(start 90.210132 -209.96529)
		(end 90.614754 -209.96529)
		(width 0.12954)
		(layer "B.Cu")
		(net "I3C_SPD_DDRABCD_CPU1_SCL")
	)
	(segment
		(start 107.316016 -224.404936)
		(end 107.316016 -224.373948)
		(width 0.0889)
		(layer "B.Cu")
		(net "I3C_SPD_DDRABCD_CPU1_SCL")
	)
	(segment
		(start 107.59821 -223.899984)
		(end 107.6071 -223.894904)
		(width 0.0889)
		(layer "B.Cu")
		(net "I3C_SPD_DDRABCD_CPU1_SCL")
	)
	(segment
		(start 103.8479 -220.000576)
		(end 103.83901 -219.995496)
		(width 0.0889)
		(layer "B.Cu")
		(net "I3C_SPD_DDRABCD_CPU1_SCL")
	)
	(segment
		(start 92.804488 -207.775556)
		(end 92.804488 -203.001118)
		(width 0.12954)
		(layer "B.Cu")
		(net "I3C_SPD_DDRABCD_CPU1_SCL")
	)
	(segment
		(start 85.990684 -214.184738)
		(end 90.210132 -209.96529)
		(width 0.12954)
		(layer "B.Cu")
		(net "I3C_SPD_DDRABCD_CPU1_SCL")
	)
	(segment
		(start 87.407242 -217.562684)
		(end 87.392256 -217.554048)
		(width 0.0889)
		(layer "B.Cu")
		(net "I3C_SPD_DDRABCD_CPU1_SCL")
	)
	(segment
		(start 92.177108 -191.105282)
		(end 93.193108 -191.105282)
		(width 0.12954)
		(layer "B.Cu")
		(net "I3C_SPD_DDRABCD_CPU1_SCL")
	)
	(segment
		(start 103.464614 -219.995496)
		(end 103.4542 -220.001592)
		(width 0.0889)
		(layer "B.Cu")
		(net "I3C_SPD_DDRABCD_CPU1_SCL")
	)
	(segment
		(start 90.307414 -219.995496)
		(end 90.297 -220.001592)
		(width 0.0889)
		(layer "B.Cu")
		(net "I3C_SPD_DDRABCD_CPU1_SCL")
	)
	(segment
		(start 107.6071 -223.256348)
		(end 107.59821 -223.251268)
		(width 0.0889)
		(layer "B.Cu")
		(net "I3C_SPD_DDRABCD_CPU1_SCL")
	)
	(segment
		(start 109.947964 -228.948488)
		(end 109.941868 -228.944932)
		(width 0.0889)
		(layer "B.Cu")
		(net "I3C_SPD_DDRABCD_CPU1_SCL")
	)
	(segment
		(start 108.255816 -226.027234)
		(end 108.255816 -226.017328)
		(width 0.0889)
		(layer "B.Cu")
		(net "I3C_SPD_DDRABCD_CPU1_SCL")
	)
	(segment
		(start 110.135416 -229.28834)
		(end 110.135416 -229.272846)
		(width 0.0889)
		(layer "B.Cu")
		(net "I3C_SPD_DDRABCD_CPU1_SCL")
	)
	(segment
		(start 107.316016 -222.783654)
		(end 107.316016 -222.761556)
		(width 0.0889)
		(layer "B.Cu")
		(net "I3C_SPD_DDRABCD_CPU1_SCL")
	)
	(segment
		(start 88.520016 -219.515944)
		(end 88.520016 -219.506038)
		(width 0.0889)
		(layer "B.Cu")
		(net "I3C_SPD_DDRABCD_CPU1_SCL")
	)
	(segment
		(start 109.956854 -228.953568)
		(end 109.947964 -228.948488)
		(width 0.0889)
		(layer "B.Cu")
		(net "I3C_SPD_DDRABCD_CPU1_SCL")
	)
	(segment
		(start 107.6071 -224.88398)
		(end 107.59821 -224.8789)
		(width 0.0889)
		(layer "B.Cu")
		(net "I3C_SPD_DDRABCD_CPU1_SCL")
	)
	(segment
		(start 107.785662 -225.217482)
		(end 107.785662 -225.203258)
		(width 0.0889)
		(layer "B.Cu")
		(net "I3C_SPD_DDRABCD_CPU1_SCL")
	)
	(segment
		(start 86.640162 -216.250774)
		(end 86.640162 -216.074752)
		(width 0.0889)
		(layer "B.Cu")
		(net "I3C_SPD_DDRABCD_CPU1_SCL")
	)
	(segment
		(start 107.137454 -222.442278)
		(end 107.128564 -222.437198)
		(width 0.0889)
		(layer "B.Cu")
		(net "I3C_SPD_DDRABCD_CPU1_SCL")
	)
	(segment
		(start 106.188764 -222.437198)
		(end 106.182668 -222.433642)
		(width 0.0889)
		(layer "B.Cu")
		(net "I3C_SPD_DDRABCD_CPU1_SCL")
	)
	(segment
		(start 91.247468 -219.995496)
		(end 91.237054 -220.001592)
		(width 0.0889)
		(layer "B.Cu")
		(net "I3C_SPD_DDRABCD_CPU1_SCL")
	)
	(segment
		(start 100.645468 -219.995496)
		(end 100.635054 -220.001592)
		(width 0.0889)
		(layer "B.Cu")
		(net "I3C_SPD_DDRABCD_CPU1_SCL")
	)
	(segment
		(start 96.886268 -219.995496)
		(end 96.875854 -220.001592)
		(width 0.0889)
		(layer "B.Cu")
		(net "I3C_SPD_DDRABCD_CPU1_SCL")
	)
	(segment
		(start 91.939618 -195.231004)
		(end 92.85732 -194.313302)
		(width 0.12954)
		(layer "B.Cu")
		(net "I3C_SPD_DDRABCD_CPU1_SCL")
	)
	(segment
		(start 92.85732 -191.785494)
		(end 92.177108 -191.105282)
		(width 0.12954)
		(layer "B.Cu")
		(net "I3C_SPD_DDRABCD_CPU1_SCL")
	)
	(segment
		(start 102.525068 -219.995496)
		(end 102.514654 -220.001592)
		(width 0.0889)
		(layer "B.Cu")
		(net "I3C_SPD_DDRABCD_CPU1_SCL")
	)
	(segment
		(start 109.47781 -227.155502)
		(end 109.4867 -227.150422)
		(width 0.0889)
		(layer "B.Cu")
		(net "I3C_SPD_DDRABCD_CPU1_SCL")
	)
	(segment
		(start 93.127068 -219.995496)
		(end 93.116654 -220.001592)
		(width 0.0889)
		(layer "B.Cu")
		(net "I3C_SPD_DDRABCD_CPU1_SCL")
	)
	(segment
		(start 88.341454 -219.18676)
		(end 88.332564 -219.18168)
		(width 0.0889)
		(layer "B.Cu")
		(net "I3C_SPD_DDRABCD_CPU1_SCL")
	)
	(segment
		(start 88.050116 -218.702128)
		(end 88.050116 -218.692222)
		(width 0.0889)
		(layer "B.Cu")
		(net "I3C_SPD_DDRABCD_CPU1_SCL")
	)
	(segment
		(start 99.705414 -219.995496)
		(end 99.695 -220.001592)
		(width 0.0889)
		(layer "B.Cu")
		(net "I3C_SPD_DDRABCD_CPU1_SCL")
	)
	(segment
		(start 95.006668 -219.995496)
		(end 94.996254 -220.001592)
		(width 0.0889)
		(layer "B.Cu")
		(net "I3C_SPD_DDRABCD_CPU1_SCL")
	)
	(segment
		(start 87.871554 -218.372944)
		(end 87.862664 -218.367864)
		(width 0.0889)
		(layer "B.Cu")
		(net "I3C_SPD_DDRABCD_CPU1_SCL")
	)
	(segment
		(start 87.862664 -218.367864)
		(end 87.850472 -218.360752)
		(width 0.0889)
		(layer "B.Cu")
		(net "I3C_SPD_DDRABCD_CPU1_SCL")
	)
	(segment
		(start 105.7275 -221.628462)
		(end 105.71861 -221.623382)
		(width 0.0889)
		(layer "B.Cu")
		(net "I3C_SPD_DDRABCD_CPU1_SCL")
	)
	(segment
		(start 94.066614 -219.995496)
		(end 94.0562 -220.001592)
		(width 0.0889)
		(layer "B.Cu")
		(net "I3C_SPD_DDRABCD_CPU1_SCL")
	)
	(segment
		(start 92.85732 -194.313302)
		(end 92.85732 -191.785494)
		(width 0.12954)
		(layer "B.Cu")
		(net "I3C_SPD_DDRABCD_CPU1_SCL")
	)
	(segment
		(start 97.825814 -219.995496)
		(end 97.8154 -220.001592)
		(width 0.0889)
		(layer "B.Cu")
		(net "I3C_SPD_DDRABCD_CPU1_SCL")
	)
	(segment
		(start 86.640416 -216.266268)
		(end 86.640162 -216.250774)
		(width 0.0889)
		(layer "B.Cu")
		(net "I3C_SPD_DDRABCD_CPU1_SCL")
	)
	(segment
		(start 108.077254 -225.69805)
		(end 108.068364 -225.69297)
		(width 0.0889)
		(layer "B.Cu")
		(net "I3C_SPD_DDRABCD_CPU1_SCL")
	)
	(segment
		(start 109.195616 -227.667058)
		(end 109.195616 -227.629466)
		(width 0.0889)
		(layer "B.Cu")
		(net "I3C_SPD_DDRABCD_CPU1_SCL")
	)
	(segment
		(start 85.990684 -215.425274)
		(end 85.990684 -214.184738)
		(width 0.12954)
		(layer "B.Cu")
		(net "I3C_SPD_DDRABCD_CPU1_SCL")
	)
	(segment
		(start 101.585014 -219.995496)
		(end 101.5746 -220.001592)
		(width 0.0889)
		(layer "B.Cu")
		(net "I3C_SPD_DDRABCD_CPU1_SCL")
	)
	(segment
		(start 95.946214 -219.995496)
		(end 95.9358 -220.001592)
		(width 0.0889)
		(layer "B.Cu")
		(net "I3C_SPD_DDRABCD_CPU1_SCL")
	)
	(segment
		(start 92.804488 -203.001118)
		(end 92.293186 -202.489816)
		(width 0.12954)
		(layer "B.Cu")
		(net "I3C_SPD_DDRABCD_CPU1_SCL")
	)
	(segment
		(start 92.187014 -219.995496)
		(end 92.1766 -220.001592)
		(width 0.0889)
		(layer "B.Cu")
		(net "I3C_SPD_DDRABCD_CPU1_SCL")
	)
	(segment
		(start 109.103414 -226.506786)
		(end 109.093 -226.512882)
		(width 0.0889)
		(layer "B.Cu")
		(net "I3C_SPD_DDRABCD_CPU1_SCL")
	)
	(segment
		(start 86.9315 -216.745058)
		(end 86.92261 -216.739978)
		(width 0.0889)
		(layer "B.Cu")
		(net "I3C_SPD_DDRABCD_CPU1_SCL")
	)
	(segment
		(start 91.939618 -202.136248)
		(end 91.939618 -195.231004)
		(width 0.12954)
		(layer "B.Cu")
		(net "I3C_SPD_DDRABCD_CPU1_SCL")
	)
	(segment
		(start 110.4265 -229.767384)
		(end 110.423198 -229.765606)
		(width 0.0889)
		(layer "B.Cu")
		(net "I3C_SPD_DDRABCD_CPU1_SCL")
	)
	(segment
		(start 86.640162 -216.074752)
		(end 85.990684 -215.425274)
		(width 0.0889)
		(layer "B.Cu")
		(net "I3C_SPD_DDRABCD_CPU1_SCL")
	)
	(arc
		(start 108.255816 -226.017328)
		(mid 108.208137 -225.834428)
		(end 108.077254 -225.69805)
		(width 0.0889)
		(layer "B.Cu")
		(net "I3C_SPD_DDRABCD_CPU1_SCL")
	)
	(arc
		(start 87.110062 -217.064336)
		(mid 87.062383 -216.881436)
		(end 86.9315 -216.745058)
		(width 0.0889)
		(layer "B.Cu")
		(net "I3C_SPD_DDRABCD_CPU1_SCL")
	)
	(arc
		(start 104.026462 -220.319854)
		(mid 103.978783 -220.136954)
		(end 103.8479 -220.000576)
		(width 0.0889)
		(layer "B.Cu")
		(net "I3C_SPD_DDRABCD_CPU1_SCL")
	)
	(arc
		(start 101.5746 -220.001592)
		(mid 101.296422 -220.071315)
		(end 101.019864 -219.995496)
		(width 0.0889)
		(layer "B.Cu")
		(net "I3C_SPD_DDRABCD_CPU1_SCL")
	)
	(arc
		(start 110.41761 -229.762304)
		(mid 110.214787 -229.562073)
		(end 110.135416 -229.28834)
		(width 0.0889)
		(layer "B.Cu")
		(net "I3C_SPD_DDRABCD_CPU1_SCL")
	)
	(arc
		(start 108.068364 -225.69297)
		(mid 107.864883 -225.492166)
		(end 107.785662 -225.217482)
		(width 0.0889)
		(layer "B.Cu")
		(net "I3C_SPD_DDRABCD_CPU1_SCL")
	)
	(arc
		(start 88.802464 -219.995496)
		(mid 88.598129 -219.792891)
		(end 88.520016 -219.515944)
		(width 0.0889)
		(layer "B.Cu")
		(net "I3C_SPD_DDRABCD_CPU1_SCL")
	)
	(arc
		(start 97.8154 -220.001592)
		(mid 97.537222 -220.071315)
		(end 97.260664 -219.995496)
		(width 0.0889)
		(layer "B.Cu")
		(net "I3C_SPD_DDRABCD_CPU1_SCL")
	)
	(arc
		(start 109.47781 -228.134672)
		(mid 109.276528 -227.937185)
		(end 109.195616 -227.667058)
		(width 0.0889)
		(layer "B.Cu")
		(net "I3C_SPD_DDRABCD_CPU1_SCL")
	)
	(arc
		(start 107.6071 -223.894904)
		(mid 107.785697 -223.575626)
		(end 107.6071 -223.256348)
		(width 0.0889)
		(layer "B.Cu")
		(net "I3C_SPD_DDRABCD_CPU1_SCL")
	)
	(arc
		(start 91.621864 -219.995496)
		(mid 91.434666 -219.945353)
		(end 91.247468 -219.995496)
		(width 0.0889)
		(layer "B.Cu")
		(net "I3C_SPD_DDRABCD_CPU1_SCL")
	)
	(arc
		(start 91.237054 -220.001592)
		(mid 90.958622 -220.071438)
		(end 90.68181 -219.995496)
		(width 0.0889)
		(layer "B.Cu")
		(net "I3C_SPD_DDRABCD_CPU1_SCL")
	)
	(arc
		(start 92.1766 -220.001592)
		(mid 91.898422 -220.071315)
		(end 91.621864 -219.995496)
		(width 0.0889)
		(layer "B.Cu")
		(net "I3C_SPD_DDRABCD_CPU1_SCL")
	)
	(arc
		(start 98.20021 -219.995496)
		(mid 98.013012 -219.945353)
		(end 97.825814 -219.995496)
		(width 0.0889)
		(layer "B.Cu")
		(net "I3C_SPD_DDRABCD_CPU1_SCL")
	)
	(arc
		(start 105.906062 -221.94774)
		(mid 105.858383 -221.76484)
		(end 105.7275 -221.628462)
		(width 0.0889)
		(layer "B.Cu")
		(net "I3C_SPD_DDRABCD_CPU1_SCL")
	)
	(arc
		(start 88.332564 -219.18168)
		(mid 88.128229 -218.979075)
		(end 88.050116 -218.702128)
		(width 0.0889)
		(layer "B.Cu")
		(net "I3C_SPD_DDRABCD_CPU1_SCL")
	)
	(arc
		(start 104.874568 -220.809566)
		(mid 104.591866 -220.885308)
		(end 104.309164 -220.809566)
		(width 0.0889)
		(layer "B.Cu")
		(net "I3C_SPD_DDRABCD_CPU1_SCL")
	)
	(arc
		(start 105.248964 -220.809566)
		(mid 105.061766 -220.759423)
		(end 104.874568 -220.809566)
		(width 0.0889)
		(layer "B.Cu")
		(net "I3C_SPD_DDRABCD_CPU1_SCL")
	)
	(arc
		(start 102.514654 -220.001592)
		(mid 102.236222 -220.071438)
		(end 101.95941 -219.995496)
		(width 0.0889)
		(layer "B.Cu")
		(net "I3C_SPD_DDRABCD_CPU1_SCL")
	)
	(arc
		(start 100.07981 -219.995496)
		(mid 99.892612 -219.945353)
		(end 99.705414 -219.995496)
		(width 0.0889)
		(layer "B.Cu")
		(net "I3C_SPD_DDRABCD_CPU1_SCL")
	)
	(arc
		(start 109.195616 -227.629466)
		(mid 109.274986 -227.355732)
		(end 109.47781 -227.155502)
		(width 0.0889)
		(layer "B.Cu")
		(net "I3C_SPD_DDRABCD_CPU1_SCL")
	)
	(arc
		(start 90.68181 -219.995496)
		(mid 90.494612 -219.945353)
		(end 90.307414 -219.995496)
		(width 0.0889)
		(layer "B.Cu")
		(net "I3C_SPD_DDRABCD_CPU1_SCL")
	)
	(arc
		(start 109.4867 -227.150422)
		(mid 109.665297 -226.831144)
		(end 109.4867 -226.511866)
		(width 0.0889)
		(layer "B.Cu")
		(net "I3C_SPD_DDRABCD_CPU1_SCL")
	)
	(arc
		(start 106.754168 -222.437198)
		(mid 106.479969 -222.513033)
		(end 106.203496 -222.445834)
		(width 0.0889)
		(layer "B.Cu")
		(net "I3C_SPD_DDRABCD_CPU1_SCL")
	)
	(arc
		(start 107.316016 -224.373948)
		(mid 107.395386 -224.100214)
		(end 107.59821 -223.899984)
		(width 0.0889)
		(layer "B.Cu")
		(net "I3C_SPD_DDRABCD_CPU1_SCL")
	)
	(arc
		(start 105.71861 -221.623382)
		(mid 105.515787 -221.423151)
		(end 105.436416 -221.149418)
		(width 0.0889)
		(layer "B.Cu")
		(net "I3C_SPD_DDRABCD_CPU1_SCL")
	)
	(arc
		(start 92.56141 -219.995496)
		(mid 92.374212 -219.945353)
		(end 92.187014 -219.995496)
		(width 0.0889)
		(layer "B.Cu")
		(net "I3C_SPD_DDRABCD_CPU1_SCL")
	)
	(arc
		(start 90.297 -220.001592)
		(mid 90.018822 -220.071315)
		(end 89.742264 -219.995496)
		(width 0.0889)
		(layer "B.Cu")
		(net "I3C_SPD_DDRABCD_CPU1_SCL")
	)
	(arc
		(start 107.128564 -222.437198)
		(mid 106.941366 -222.387055)
		(end 106.754168 -222.437198)
		(width 0.0889)
		(layer "B.Cu")
		(net "I3C_SPD_DDRABCD_CPU1_SCL")
	)
	(arc
		(start 109.941868 -228.944932)
		(mid 109.739281 -228.738581)
		(end 109.665262 -228.45903)
		(width 0.0889)
		(layer "B.Cu")
		(net "I3C_SPD_DDRABCD_CPU1_SCL")
	)
	(arc
		(start 106.182668 -222.433642)
		(mid 105.980081 -222.227291)
		(end 105.906062 -221.94774)
		(width 0.0889)
		(layer "B.Cu")
		(net "I3C_SPD_DDRABCD_CPU1_SCL")
	)
	(arc
		(start 96.32061 -219.995496)
		(mid 96.133412 -219.945353)
		(end 95.946214 -219.995496)
		(width 0.0889)
		(layer "B.Cu")
		(net "I3C_SPD_DDRABCD_CPU1_SCL")
	)
	(arc
		(start 89.367868 -219.995496)
		(mid 89.085166 -220.071272)
		(end 88.802464 -219.995496)
		(width 0.0889)
		(layer "B.Cu")
		(net "I3C_SPD_DDRABCD_CPU1_SCL")
	)
	(arc
		(start 95.381064 -219.995496)
		(mid 95.193866 -219.945353)
		(end 95.006668 -219.995496)
		(width 0.0889)
		(layer "B.Cu")
		(net "I3C_SPD_DDRABCD_CPU1_SCL")
	)
	(arc
		(start 103.83901 -219.995496)
		(mid 103.651812 -219.945353)
		(end 103.464614 -219.995496)
		(width 0.0889)
		(layer "B.Cu")
		(net "I3C_SPD_DDRABCD_CPU1_SCL")
	)
	(arc
		(start 101.95941 -219.995496)
		(mid 101.772212 -219.945353)
		(end 101.585014 -219.995496)
		(width 0.0889)
		(layer "B.Cu")
		(net "I3C_SPD_DDRABCD_CPU1_SCL")
	)
	(arc
		(start 110.617762 -230.20528)
		(mid 110.608275 -230.146307)
		(end 110.605062 -230.086662)
		(width 0.0889)
		(layer "B.Cu")
		(net "I3C_SPD_DDRABCD_CPU1_SCL")
	)
	(arc
		(start 102.899464 -219.995496)
		(mid 102.712266 -219.945353)
		(end 102.525068 -219.995496)
		(width 0.0889)
		(layer "B.Cu")
		(net "I3C_SPD_DDRABCD_CPU1_SCL")
	)
	(arc
		(start 94.0562 -220.001592)
		(mid 93.778022 -220.071315)
		(end 93.501464 -219.995496)
		(width 0.0889)
		(layer "B.Cu")
		(net "I3C_SPD_DDRABCD_CPU1_SCL")
	)
	(arc
		(start 87.392256 -217.554048)
		(mid 87.190974 -217.356561)
		(end 87.110062 -217.086434)
		(width 0.0889)
		(layer "B.Cu")
		(net "I3C_SPD_DDRABCD_CPU1_SCL")
	)
	(arc
		(start 97.260664 -219.995496)
		(mid 97.073466 -219.945353)
		(end 96.886268 -219.995496)
		(width 0.0889)
		(layer "B.Cu")
		(net "I3C_SPD_DDRABCD_CPU1_SCL")
	)
	(arc
		(start 96.875854 -220.001592)
		(mid 96.597422 -220.071438)
		(end 96.32061 -219.995496)
		(width 0.0889)
		(layer "B.Cu")
		(net "I3C_SPD_DDRABCD_CPU1_SCL")
	)
	(arc
		(start 94.996254 -220.001592)
		(mid 94.717822 -220.071438)
		(end 94.44101 -219.995496)
		(width 0.0889)
		(layer "B.Cu")
		(net "I3C_SPD_DDRABCD_CPU1_SCL")
	)
	(arc
		(start 107.59821 -224.8789)
		(mid 107.395387 -224.678669)
		(end 107.316016 -224.404936)
		(width 0.0889)
		(layer "B.Cu")
		(net "I3C_SPD_DDRABCD_CPU1_SCL")
	)
	(arc
		(start 109.093 -226.512882)
		(mid 108.814822 -226.582605)
		(end 108.538264 -226.506786)
		(width 0.0889)
		(layer "B.Cu")
		(net "I3C_SPD_DDRABCD_CPU1_SCL")
	)
	(arc
		(start 110.605062 -230.086662)
		(mid 110.557383 -229.903762)
		(end 110.4265 -229.767384)
		(width 0.0889)
		(layer "B.Cu")
		(net "I3C_SPD_DDRABCD_CPU1_SCL")
	)
	(arc
		(start 107.59821 -223.251268)
		(mid 107.396928 -223.053781)
		(end 107.316016 -222.783654)
		(width 0.0889)
		(layer "B.Cu")
		(net "I3C_SPD_DDRABCD_CPU1_SCL")
	)
	(arc
		(start 107.316016 -222.761556)
		(mid 107.268337 -222.578656)
		(end 107.137454 -222.442278)
		(width 0.0889)
		(layer "B.Cu")
		(net "I3C_SPD_DDRABCD_CPU1_SCL")
	)
	(arc
		(start 86.92261 -216.739978)
		(mid 86.719857 -216.539866)
		(end 86.640416 -216.266268)
		(width 0.0889)
		(layer "B.Cu")
		(net "I3C_SPD_DDRABCD_CPU1_SCL")
	)
	(arc
		(start 87.850472 -218.360752)
		(mid 87.652244 -218.154904)
		(end 87.579962 -217.878406)
		(width 0.0889)
		(layer "B.Cu")
		(net "I3C_SPD_DDRABCD_CPU1_SCL")
	)
	(arc
		(start 98.755454 -220.001592)
		(mid 98.477022 -220.071438)
		(end 98.20021 -219.995496)
		(width 0.0889)
		(layer "B.Cu")
		(net "I3C_SPD_DDRABCD_CPU1_SCL")
	)
	(arc
		(start 109.665262 -228.45903)
		(mid 109.617583 -228.27613)
		(end 109.4867 -228.139752)
		(width 0.0889)
		(layer "B.Cu")
		(net "I3C_SPD_DDRABCD_CPU1_SCL")
	)
	(arc
		(start 89.742264 -219.995496)
		(mid 89.555066 -219.945353)
		(end 89.367868 -219.995496)
		(width 0.0889)
		(layer "B.Cu")
		(net "I3C_SPD_DDRABCD_CPU1_SCL")
	)
	(arc
		(start 110.135416 -229.272846)
		(mid 110.087737 -229.089946)
		(end 109.956854 -228.953568)
		(width 0.0889)
		(layer "B.Cu")
		(net "I3C_SPD_DDRABCD_CPU1_SCL")
	)
	(arc
		(start 93.501464 -219.995496)
		(mid 93.314266 -219.945353)
		(end 93.127068 -219.995496)
		(width 0.0889)
		(layer "B.Cu")
		(net "I3C_SPD_DDRABCD_CPU1_SCL")
	)
	(arc
		(start 107.785662 -225.203258)
		(mid 107.737983 -225.020358)
		(end 107.6071 -224.88398)
		(width 0.0889)
		(layer "B.Cu")
		(net "I3C_SPD_DDRABCD_CPU1_SCL")
	)
	(arc
		(start 88.050116 -218.692222)
		(mid 88.002437 -218.509322)
		(end 87.871554 -218.372944)
		(width 0.0889)
		(layer "B.Cu")
		(net "I3C_SPD_DDRABCD_CPU1_SCL")
	)
	(arc
		(start 95.9358 -220.001592)
		(mid 95.657622 -220.071315)
		(end 95.381064 -219.995496)
		(width 0.0889)
		(layer "B.Cu")
		(net "I3C_SPD_DDRABCD_CPU1_SCL")
	)
	(arc
		(start 108.538264 -226.506786)
		(mid 108.333929 -226.304181)
		(end 108.255816 -226.027234)
		(width 0.0889)
		(layer "B.Cu")
		(net "I3C_SPD_DDRABCD_CPU1_SCL")
	)
	(arc
		(start 94.44101 -219.995496)
		(mid 94.253812 -219.945353)
		(end 94.066614 -219.995496)
		(width 0.0889)
		(layer "B.Cu")
		(net "I3C_SPD_DDRABCD_CPU1_SCL")
	)
	(arc
		(start 99.140264 -219.995496)
		(mid 98.953066 -219.945353)
		(end 98.765868 -219.995496)
		(width 0.0889)
		(layer "B.Cu")
		(net "I3C_SPD_DDRABCD_CPU1_SCL")
	)
	(arc
		(start 109.47781 -226.506786)
		(mid 109.290612 -226.456643)
		(end 109.103414 -226.506786)
		(width 0.0889)
		(layer "B.Cu")
		(net "I3C_SPD_DDRABCD_CPU1_SCL")
	)
	(arc
		(start 104.309164 -220.809566)
		(mid 104.104092 -220.605887)
		(end 104.026462 -220.327474)
		(width 0.0889)
		(layer "B.Cu")
		(net "I3C_SPD_DDRABCD_CPU1_SCL")
	)
	(arc
		(start 105.436416 -221.133924)
		(mid 105.388737 -220.951024)
		(end 105.257854 -220.814646)
		(width 0.0889)
		(layer "B.Cu")
		(net "I3C_SPD_DDRABCD_CPU1_SCL")
	)
	(arc
		(start 88.520016 -219.506038)
		(mid 88.472337 -219.323138)
		(end 88.341454 -219.18676)
		(width 0.0889)
		(layer "B.Cu")
		(net "I3C_SPD_DDRABCD_CPU1_SCL")
	)
	(arc
		(start 93.116654 -220.001592)
		(mid 92.838222 -220.071438)
		(end 92.56141 -219.995496)
		(width 0.0889)
		(layer "B.Cu")
		(net "I3C_SPD_DDRABCD_CPU1_SCL")
	)
	(arc
		(start 100.635054 -220.001592)
		(mid 100.356622 -220.071438)
		(end 100.07981 -219.995496)
		(width 0.0889)
		(layer "B.Cu")
		(net "I3C_SPD_DDRABCD_CPU1_SCL")
	)
	(arc
		(start 99.695 -220.001592)
		(mid 99.416822 -220.071315)
		(end 99.140264 -219.995496)
		(width 0.0889)
		(layer "B.Cu")
		(net "I3C_SPD_DDRABCD_CPU1_SCL")
	)
	(arc
		(start 103.4542 -220.001592)
		(mid 103.176022 -220.071315)
		(end 102.899464 -219.995496)
		(width 0.0889)
		(layer "B.Cu")
		(net "I3C_SPD_DDRABCD_CPU1_SCL")
	)
	(arc
		(start 87.579962 -217.878406)
		(mid 87.533958 -217.698469)
		(end 87.407242 -217.562684)
		(width 0.0889)
		(layer "B.Cu")
		(net "I3C_SPD_DDRABCD_CPU1_SCL")
	)
	(arc
		(start 101.019864 -219.995496)
		(mid 100.832666 -219.945353)
		(end 100.645468 -219.995496)
		(width 0.0889)
		(layer "B.Cu")
		(net "I3C_SPD_DDRABCD_CPU1_SCL")
	)
	(segment
		(start 76.33208 -140.274548)
		(end 76.560934 -140.274548)
		(width 0.12954)
		(layer "F.Cu")
		(net "I3C_SPD_DDRABCD_CPU1_R_SDA")
	)
	(segment
		(start 76.560934 -140.274548)
		(end 77.966824 -141.680438)
		(width 0.12954)
		(layer "F.Cu")
		(net "I3C_SPD_DDRABCD_CPU1_R_SDA")
	)
	(segment
		(start 78.598268 -142.210536)
		(end 79.404464 -143.016732)
		(width 0.12954)
		(layer "F.Cu")
		(net "I3C_SPD_DDRABCD_CPU1_R_SDA")
	)
	(segment
		(start 78.301596 -147.360132)
		(end 76.999338 -147.360132)
		(width 0.12954)
		(layer "F.Cu")
		(net "I3C_SPD_DDRABCD_CPU1_R_SDA")
	)
	(segment
		(start 77.966824 -141.680438)
		(end 77.966824 -142.187168)
		(width 0.12954)
		(layer "F.Cu")
		(net "I3C_SPD_DDRABCD_CPU1_R_SDA")
	)
	(segment
		(start 79.404464 -143.016732)
		(end 79.404464 -146.257264)
		(width 0.12954)
		(layer "F.Cu")
		(net "I3C_SPD_DDRABCD_CPU1_R_SDA")
	)
	(segment
		(start 77.990192 -142.210536)
		(end 78.598268 -142.210536)
		(width 0.12954)
		(layer "F.Cu")
		(net "I3C_SPD_DDRABCD_CPU1_R_SDA")
	)
	(segment
		(start 79.404464 -146.257264)
		(end 78.301596 -147.360132)
		(width 0.12954)
		(layer "F.Cu")
		(net "I3C_SPD_DDRABCD_CPU1_R_SDA")
	)
	(segment
		(start 77.966824 -142.187168)
		(end 77.990192 -142.210536)
		(width 0.12954)
		(layer "F.Cu")
		(net "I3C_SPD_DDRABCD_CPU1_R_SDA")
	)
	(via
		(at 76.33208 -140.274548)
		(size 0.508)
		(drill 0.254)
		(layers "F.Cu" "B.Cu")
		(net "I3C_SPD_DDRABCD_CPU1_R_SDA")
	)
	(via
		(at 91.161108 -187.00115)
		(size 0.508)
		(drill 0.254)
		(layers "F.Cu" "B.Cu")
		(net "I3C_SPD_DDRABCD_CPU1_R_SDA")
	)
	(segment
		(start 93.809058 -187.00115)
		(end 95.225108 -188.4172)
		(width 0.12954)
		(layer "B.Cu")
		(net "I3C_SPD_DDRABCD_CPU1_R_SDA")
	)
	(segment
		(start 95.225108 -188.4172)
		(end 95.225108 -190.305182)
		(width 0.12954)
		(layer "B.Cu")
		(net "I3C_SPD_DDRABCD_CPU1_R_SDA")
	)
	(segment
		(start 91.161108 -187.00115)
		(end 93.809058 -187.00115)
		(width 0.12954)
		(layer "B.Cu")
		(net "I3C_SPD_DDRABCD_CPU1_R_SDA")
	)
	(segment
		(start 87.000842 -174.973234)
		(end 87.000842 -162.018218)
		(width 0.127)
		(layer "In2.Cu")
		(net "I3C_SPD_DDRABCD_CPU1_R_SDA")
	)
	(segment
		(start 91.161108 -187.00115)
		(end 90.52179 -187.640468)
		(width 0.127)
		(layer "In2.Cu")
		(net "I3C_SPD_DDRABCD_CPU1_R_SDA")
	)
	(segment
		(start 87.5284 -186.480704)
		(end 86.65083 -185.603134)
		(width 0.127)
		(layer "In2.Cu")
		(net "I3C_SPD_DDRABCD_CPU1_R_SDA")
	)
	(segment
		(start 82.48904 -147.405852)
		(end 81.800192 -145.74266)
		(width 0.127)
		(layer "In2.Cu")
		(net "I3C_SPD_DDRABCD_CPU1_R_SDA")
	)
	(segment
		(start 81.800192 -145.74266)
		(end 76.33208 -140.274548)
		(width 0.127)
		(layer "In2.Cu")
		(net "I3C_SPD_DDRABCD_CPU1_R_SDA")
	)
	(segment
		(start 82.48904 -157.506416)
		(end 82.48904 -147.405852)
		(width 0.127)
		(layer "In2.Cu")
		(net "I3C_SPD_DDRABCD_CPU1_R_SDA")
	)
	(segment
		(start 87.5284 -187.025788)
		(end 87.5284 -186.480704)
		(width 0.127)
		(layer "In2.Cu")
		(net "I3C_SPD_DDRABCD_CPU1_R_SDA")
	)
	(segment
		(start 88.14308 -187.640468)
		(end 87.5284 -187.025788)
		(width 0.127)
		(layer "In2.Cu")
		(net "I3C_SPD_DDRABCD_CPU1_R_SDA")
	)
	(segment
		(start 90.52179 -187.640468)
		(end 88.14308 -187.640468)
		(width 0.127)
		(layer "In2.Cu")
		(net "I3C_SPD_DDRABCD_CPU1_R_SDA")
	)
	(segment
		(start 86.65083 -175.323246)
		(end 87.000842 -174.973234)
		(width 0.127)
		(layer "In2.Cu")
		(net "I3C_SPD_DDRABCD_CPU1_R_SDA")
	)
	(segment
		(start 87.000842 -162.018218)
		(end 82.48904 -157.506416)
		(width 0.127)
		(layer "In2.Cu")
		(net "I3C_SPD_DDRABCD_CPU1_R_SDA")
	)
	(segment
		(start 86.65083 -185.603134)
		(end 86.65083 -175.323246)
		(width 0.127)
		(layer "In2.Cu")
		(net "I3C_SPD_DDRABCD_CPU1_R_SDA")
	)
	(segment
		(start 76.999338 -149.265132)
		(end 77.817218 -149.265132)
		(width 0.12954)
		(layer "F.Cu")
		(net "I3C_SPD_DDRABCD_CPU1_R_SCL")
	)
	(segment
		(start 77.89037 -150.43277)
		(end 77.760576 -150.562564)
		(width 0.12954)
		(layer "F.Cu")
		(net "I3C_SPD_DDRABCD_CPU1_R_SCL")
	)
	(segment
		(start 77.760576 -150.562564)
		(end 77.760576 -151.210772)
		(width 0.12954)
		(layer "F.Cu")
		(net "I3C_SPD_DDRABCD_CPU1_R_SCL")
	)
	(segment
		(start 78.345538 -149.793452)
		(end 78.345538 -150.43277)
		(width 0.12954)
		(layer "F.Cu")
		(net "I3C_SPD_DDRABCD_CPU1_R_SCL")
	)
	(segment
		(start 78.345538 -150.43277)
		(end 77.89037 -150.43277)
		(width 0.12954)
		(layer "F.Cu")
		(net "I3C_SPD_DDRABCD_CPU1_R_SCL")
	)
	(segment
		(start 77.817218 -149.265132)
		(end 78.345538 -149.793452)
		(width 0.12954)
		(layer "F.Cu")
		(net "I3C_SPD_DDRABCD_CPU1_R_SCL")
	)
	(via
		(at 91.161108 -188.73089)
		(size 0.508)
		(drill 0.254)
		(layers "F.Cu" "B.Cu")
		(net "I3C_SPD_DDRABCD_CPU1_R_SCL")
	)
	(via
		(at 78.345538 -150.43277)
		(size 0.508)
		(drill 0.254)
		(layers "F.Cu" "B.Cu")
		(net "I3C_SPD_DDRABCD_CPU1_R_SCL")
	)
	(segment
		(start 92.512642 -188.73089)
		(end 93.193108 -189.411356)
		(width 0.12954)
		(layer "B.Cu")
		(net "I3C_SPD_DDRABCD_CPU1_R_SCL")
	)
	(segment
		(start 91.161108 -188.73089)
		(end 92.512642 -188.73089)
		(width 0.12954)
		(layer "B.Cu")
		(net "I3C_SPD_DDRABCD_CPU1_R_SCL")
	)
	(segment
		(start 93.193108 -189.411356)
		(end 93.193108 -190.305182)
		(width 0.12954)
		(layer "B.Cu")
		(net "I3C_SPD_DDRABCD_CPU1_R_SCL")
	)
	(segment
		(start 91.161108 -188.73089)
		(end 87.326978 -188.73089)
		(width 0.127)
		(layer "In2.Cu")
		(net "I3C_SPD_DDRABCD_CPU1_R_SCL")
	)
	(segment
		(start 86.156038 -172.235114)
		(end 84.97062 -172.235114)
		(width 0.127)
		(layer "In2.Cu")
		(net "I3C_SPD_DDRABCD_CPU1_R_SCL")
	)
	(segment
		(start 84.97062 -173.505114)
		(end 84.84362 -173.378114)
		(width 0.127)
		(layer "In2.Cu")
		(net "I3C_SPD_DDRABCD_CPU1_R_SCL")
	)
	(segment
		(start 84.84362 -170.838114)
		(end 84.84362 -170.457114)
		(width 0.127)
		(layer "In2.Cu")
		(net "I3C_SPD_DDRABCD_CPU1_R_SCL")
	)
	(segment
		(start 84.84362 -170.457114)
		(end 84.97062 -170.330114)
		(width 0.127)
		(layer "In2.Cu")
		(net "I3C_SPD_DDRABCD_CPU1_R_SCL")
	)
	(segment
		(start 86.156038 -169.060114)
		(end 86.283038 -168.933114)
		(width 0.127)
		(layer "In2.Cu")
		(net "I3C_SPD_DDRABCD_CPU1_R_SCL")
	)
	(segment
		(start 86.283038 -168.933114)
		(end 86.283038 -162.778186)
		(width 0.127)
		(layer "In2.Cu")
		(net "I3C_SPD_DDRABCD_CPU1_R_SCL")
	)
	(segment
		(start 86.283038 -174.013114)
		(end 86.283038 -173.632114)
		(width 0.127)
		(layer "In2.Cu")
		(net "I3C_SPD_DDRABCD_CPU1_R_SCL")
	)
	(segment
		(start 84.97062 -174.140114)
		(end 86.156038 -174.140114)
		(width 0.127)
		(layer "In2.Cu")
		(net "I3C_SPD_DDRABCD_CPU1_R_SCL")
	)
	(segment
		(start 86.64448 -186.72556)
		(end 86.005924 -186.087004)
		(width 0.127)
		(layer "In2.Cu")
		(net "I3C_SPD_DDRABCD_CPU1_R_SCL")
	)
	(segment
		(start 86.156038 -173.505114)
		(end 84.97062 -173.505114)
		(width 0.127)
		(layer "In2.Cu")
		(net "I3C_SPD_DDRABCD_CPU1_R_SCL")
	)
	(segment
		(start 78.345538 -154.840686)
		(end 78.345538 -150.43277)
		(width 0.127)
		(layer "In2.Cu")
		(net "I3C_SPD_DDRABCD_CPU1_R_SCL")
	)
	(segment
		(start 86.283038 -171.473114)
		(end 86.283038 -171.092114)
		(width 0.127)
		(layer "In2.Cu")
		(net "I3C_SPD_DDRABCD_CPU1_R_SCL")
	)
	(segment
		(start 85.841586 -174.775114)
		(end 84.97062 -174.775114)
		(width 0.127)
		(layer "In2.Cu")
		(net "I3C_SPD_DDRABCD_CPU1_R_SCL")
	)
	(segment
		(start 86.283038 -173.632114)
		(end 86.156038 -173.505114)
		(width 0.127)
		(layer "In2.Cu")
		(net "I3C_SPD_DDRABCD_CPU1_R_SCL")
	)
	(segment
		(start 84.97062 -170.965114)
		(end 84.84362 -170.838114)
		(width 0.127)
		(layer "In2.Cu")
		(net "I3C_SPD_DDRABCD_CPU1_R_SCL")
	)
	(segment
		(start 86.283038 -169.822114)
		(end 86.156038 -169.695114)
		(width 0.127)
		(layer "In2.Cu")
		(net "I3C_SPD_DDRABCD_CPU1_R_SCL")
	)
	(segment
		(start 86.156038 -171.600114)
		(end 86.283038 -171.473114)
		(width 0.127)
		(layer "In2.Cu")
		(net "I3C_SPD_DDRABCD_CPU1_R_SCL")
	)
	(segment
		(start 86.156038 -174.140114)
		(end 86.283038 -174.013114)
		(width 0.127)
		(layer "In2.Cu")
		(net "I3C_SPD_DDRABCD_CPU1_R_SCL")
	)
	(segment
		(start 86.156038 -170.330114)
		(end 86.283038 -170.203114)
		(width 0.127)
		(layer "In2.Cu")
		(net "I3C_SPD_DDRABCD_CPU1_R_SCL")
	)
	(segment
		(start 84.97062 -169.060114)
		(end 86.156038 -169.060114)
		(width 0.127)
		(layer "In2.Cu")
		(net "I3C_SPD_DDRABCD_CPU1_R_SCL")
	)
	(segment
		(start 86.283038 -171.092114)
		(end 86.156038 -170.965114)
		(width 0.127)
		(layer "In2.Cu")
		(net "I3C_SPD_DDRABCD_CPU1_R_SCL")
	)
	(segment
		(start 84.84362 -173.378114)
		(end 84.84362 -172.997114)
		(width 0.127)
		(layer "In2.Cu")
		(net "I3C_SPD_DDRABCD_CPU1_R_SCL")
	)
	(segment
		(start 84.97062 -170.330114)
		(end 86.156038 -170.330114)
		(width 0.127)
		(layer "In2.Cu")
		(net "I3C_SPD_DDRABCD_CPU1_R_SCL")
	)
	(segment
		(start 84.84362 -172.997114)
		(end 84.97062 -172.870114)
		(width 0.127)
		(layer "In2.Cu")
		(net "I3C_SPD_DDRABCD_CPU1_R_SCL")
	)
	(segment
		(start 84.84362 -169.187114)
		(end 84.97062 -169.060114)
		(width 0.127)
		(layer "In2.Cu")
		(net "I3C_SPD_DDRABCD_CPU1_R_SCL")
	)
	(segment
		(start 86.156038 -172.870114)
		(end 86.283038 -172.743114)
		(width 0.127)
		(layer "In2.Cu")
		(net "I3C_SPD_DDRABCD_CPU1_R_SCL")
	)
	(segment
		(start 86.156038 -170.965114)
		(end 84.97062 -170.965114)
		(width 0.127)
		(layer "In2.Cu")
		(net "I3C_SPD_DDRABCD_CPU1_R_SCL")
	)
	(segment
		(start 86.005924 -174.939452)
		(end 85.841586 -174.775114)
		(width 0.127)
		(layer "In2.Cu")
		(net "I3C_SPD_DDRABCD_CPU1_R_SCL")
	)
	(segment
		(start 86.283038 -172.362114)
		(end 86.156038 -172.235114)
		(width 0.127)
		(layer "In2.Cu")
		(net "I3C_SPD_DDRABCD_CPU1_R_SCL")
	)
	(segment
		(start 84.84362 -169.568114)
		(end 84.84362 -169.187114)
		(width 0.127)
		(layer "In2.Cu")
		(net "I3C_SPD_DDRABCD_CPU1_R_SCL")
	)
	(segment
		(start 86.283038 -172.743114)
		(end 86.283038 -172.362114)
		(width 0.127)
		(layer "In2.Cu")
		(net "I3C_SPD_DDRABCD_CPU1_R_SCL")
	)
	(segment
		(start 86.64448 -188.048392)
		(end 86.64448 -186.72556)
		(width 0.127)
		(layer "In2.Cu")
		(net "I3C_SPD_DDRABCD_CPU1_R_SCL")
	)
	(segment
		(start 84.97062 -171.600114)
		(end 86.156038 -171.600114)
		(width 0.127)
		(layer "In2.Cu")
		(net "I3C_SPD_DDRABCD_CPU1_R_SCL")
	)
	(segment
		(start 84.84362 -174.267114)
		(end 84.97062 -174.140114)
		(width 0.127)
		(layer "In2.Cu")
		(net "I3C_SPD_DDRABCD_CPU1_R_SCL")
	)
	(segment
		(start 84.84362 -171.727114)
		(end 84.97062 -171.600114)
		(width 0.127)
		(layer "In2.Cu")
		(net "I3C_SPD_DDRABCD_CPU1_R_SCL")
	)
	(segment
		(start 87.326978 -188.73089)
		(end 86.64448 -188.048392)
		(width 0.127)
		(layer "In2.Cu")
		(net "I3C_SPD_DDRABCD_CPU1_R_SCL")
	)
	(segment
		(start 86.283038 -170.203114)
		(end 86.283038 -169.822114)
		(width 0.127)
		(layer "In2.Cu")
		(net "I3C_SPD_DDRABCD_CPU1_R_SCL")
	)
	(segment
		(start 86.283038 -162.778186)
		(end 78.345538 -154.840686)
		(width 0.127)
		(layer "In2.Cu")
		(net "I3C_SPD_DDRABCD_CPU1_R_SCL")
	)
	(segment
		(start 84.84362 -172.108114)
		(end 84.84362 -171.727114)
		(width 0.127)
		(layer "In2.Cu")
		(net "I3C_SPD_DDRABCD_CPU1_R_SCL")
	)
	(segment
		(start 86.156038 -169.695114)
		(end 84.97062 -169.695114)
		(width 0.127)
		(layer "In2.Cu")
		(net "I3C_SPD_DDRABCD_CPU1_R_SCL")
	)
	(segment
		(start 84.97062 -172.235114)
		(end 84.84362 -172.108114)
		(width 0.127)
		(layer "In2.Cu")
		(net "I3C_SPD_DDRABCD_CPU1_R_SCL")
	)
	(segment
		(start 86.005924 -186.087004)
		(end 86.005924 -174.939452)
		(width 0.127)
		(layer "In2.Cu")
		(net "I3C_SPD_DDRABCD_CPU1_R_SCL")
	)
	(segment
		(start 84.84362 -174.648114)
		(end 84.84362 -174.267114)
		(width 0.127)
		(layer "In2.Cu")
		(net "I3C_SPD_DDRABCD_CPU1_R_SCL")
	)
	(segment
		(start 84.97062 -172.870114)
		(end 86.156038 -172.870114)
		(width 0.127)
		(layer "In2.Cu")
		(net "I3C_SPD_DDRABCD_CPU1_R_SCL")
	)
	(segment
		(start 84.97062 -174.775114)
		(end 84.84362 -174.648114)
		(width 0.127)
		(layer "In2.Cu")
		(net "I3C_SPD_DDRABCD_CPU1_R_SCL")
	)
	(segment
		(start 84.97062 -169.695114)
		(end 84.84362 -169.568114)
		(width 0.127)
		(layer "In2.Cu")
		(net "I3C_SPD_DDRABCD_CPU1_R_SCL")
	)
	(segment
		(start 30.771846 -318.016636)
		(end 29.259784 -318.016636)
		(width 0.12954)
		(layer "F.Cu")
		(net "I3C_SPD_DDRABCD_CPU1_LVC1_SDA")
	)
	(segment
		(start 17.314164 -318.016636)
		(end 15.684246 -318.016636)
		(width 0.12954)
		(layer "F.Cu")
		(net "I3C_SPD_DDRABCD_CPU1_LVC1_SDA")
	)
	(segment
		(start 11.1379 -169.065448)
		(end 13.369544 -169.065448)
		(width 0.12954)
		(layer "F.Cu")
		(net "I3C_SPD_DDRABCD_CPU1_LVC1_SDA")
	)
	(segment
		(start 44.337224 -318.016636)
		(end 45.859446 -318.016636)
		(width 0.12954)
		(layer "F.Cu")
		(net "I3C_SPD_DDRABCD_CPU1_LVC1_SDA")
	)
	(segment
		(start 13.630656 -317.587122)
		(end 13.054076 -317.587122)
		(width 0.12954)
		(layer "F.Cu")
		(net "I3C_SPD_DDRABCD_CPU1_LVC1_SDA")
	)
	(segment
		(start 47.570644 -318.016636)
		(end 45.859446 -318.016636)
		(width 0.12954)
		(layer "F.Cu")
		(net "I3C_SPD_DDRABCD_CPU1_LVC1_SDA")
	)
	(segment
		(start 52.229258 -318.016382)
		(end 51.799998 -317.587122)
		(width 0.12954)
		(layer "F.Cu")
		(net "I3C_SPD_DDRABCD_CPU1_LVC1_SDA")
	)
	(segment
		(start 48.000158 -317.587122)
		(end 47.570644 -318.016636)
		(width 0.12954)
		(layer "F.Cu")
		(net "I3C_SPD_DDRABCD_CPU1_LVC1_SDA")
	)
	(segment
		(start 14.06017 -318.016636)
		(end 13.630656 -317.587122)
		(width 0.12954)
		(layer "F.Cu")
		(net "I3C_SPD_DDRABCD_CPU1_LVC1_SDA")
	)
	(segment
		(start 55.157878 -318.016382)
		(end 53.402992 -318.016382)
		(width 0.12954)
		(layer "F.Cu")
		(net "I3C_SPD_DDRABCD_CPU1_LVC1_SDA")
	)
	(segment
		(start 41.615106 -317.587122)
		(end 43.229276 -317.587122)
		(width 0.1016)
		(layer "F.Cu")
		(net "I3C_SPD_DDRABCD_CPU1_LVC1_SDA")
	)
	(segment
		(start 49.158906 -317.587122)
		(end 48.000158 -317.587122)
		(width 0.12954)
		(layer "F.Cu")
		(net "I3C_SPD_DDRABCD_CPU1_LVC1_SDA")
	)
	(segment
		(start 33.050226 -317.587122)
		(end 32.620712 -318.016636)
		(width 0.12954)
		(layer "F.Cu")
		(net "I3C_SPD_DDRABCD_CPU1_LVC1_SDA")
	)
	(segment
		(start 3.24104 -195.550028)
		(end 3.24104 -193.012822)
		(width 0.12954)
		(layer "F.Cu")
		(net "I3C_SPD_DDRABCD_CPU1_LVC1_SDA")
	)
	(segment
		(start 34.071306 -317.587122)
		(end 33.050226 -317.587122)
		(width 0.12954)
		(layer "F.Cu")
		(net "I3C_SPD_DDRABCD_CPU1_LVC1_SDA")
	)
	(segment
		(start 38.315646 -318.016636)
		(end 37.217096 -318.016636)
		(width 0.12954)
		(layer "F.Cu")
		(net "I3C_SPD_DDRABCD_CPU1_LVC1_SDA")
	)
	(segment
		(start 28.141676 -317.587122)
		(end 26.527506 -317.587122)
		(width 0.1016)
		(layer "F.Cu")
		(net "I3C_SPD_DDRABCD_CPU1_LVC1_SDA")
	)
	(segment
		(start 4.994656 -306.664106)
		(end 5.715762 -305.943)
		(width 0.12954)
		(layer "F.Cu")
		(net "I3C_SPD_DDRABCD_CPU1_LVC1_SDA")
	)
	(segment
		(start 8.140446 -318.016636)
		(end 5.5753 -318.016636)
		(width 0.12954)
		(layer "F.Cu")
		(net "I3C_SPD_DDRABCD_CPU1_LVC1_SDA")
	)
	(segment
		(start 3.24104 -193.012822)
		(end 4.91998 -191.333882)
		(width 0.12954)
		(layer "F.Cu")
		(net "I3C_SPD_DDRABCD_CPU1_LVC1_SDA")
	)
	(segment
		(start 9.816592 -318.016636)
		(end 8.140446 -318.016636)
		(width 0.12954)
		(layer "F.Cu")
		(net "I3C_SPD_DDRABCD_CPU1_LVC1_SDA")
	)
	(segment
		(start 40.187372 -317.454788)
		(end 41.23182 -317.454788)
		(width 0.12954)
		(layer "F.Cu")
		(net "I3C_SPD_DDRABCD_CPU1_LVC1_SDA")
	)
	(segment
		(start 18.4404 -150.856188)
		(end 28.6639 -140.632688)
		(width 0.12954)
		(layer "F.Cu")
		(net "I3C_SPD_DDRABCD_CPU1_LVC1_SDA")
	)
	(segment
		(start 60.947046 -318.016636)
		(end 59.048142 -318.016636)
		(width 0.12954)
		(layer "F.Cu")
		(net "I3C_SPD_DDRABCD_CPU1_LVC1_SDA")
	)
	(segment
		(start 35.685476 -317.587122)
		(end 34.071306 -317.587122)
		(width 0.1016)
		(layer "F.Cu")
		(net "I3C_SPD_DDRABCD_CPU1_LVC1_SDA")
	)
	(segment
		(start 39.625524 -318.016636)
		(end 40.187372 -317.454788)
		(width 0.12954)
		(layer "F.Cu")
		(net "I3C_SPD_DDRABCD_CPU1_LVC1_SDA")
	)
	(segment
		(start 28.83027 -317.587122)
		(end 28.141676 -317.587122)
		(width 0.12954)
		(layer "F.Cu")
		(net "I3C_SPD_DDRABCD_CPU1_LVC1_SDA")
	)
	(segment
		(start 32.620712 -318.016636)
		(end 30.771846 -318.016636)
		(width 0.12954)
		(layer "F.Cu")
		(net "I3C_SPD_DDRABCD_CPU1_LVC1_SDA")
	)
	(segment
		(start 5.715762 -198.02475)
		(end 3.24104 -195.550028)
		(width 0.12954)
		(layer "F.Cu")
		(net "I3C_SPD_DDRABCD_CPU1_LVC1_SDA")
	)
	(segment
		(start 58.316876 -317.587122)
		(end 56.702706 -317.587122)
		(width 0.1016)
		(layer "F.Cu")
		(net "I3C_SPD_DDRABCD_CPU1_LVC1_SDA")
	)
	(segment
		(start 43.229276 -317.587122)
		(end 43.90771 -317.587122)
		(width 0.12954)
		(layer "F.Cu")
		(net "I3C_SPD_DDRABCD_CPU1_LVC1_SDA")
	)
	(segment
		(start 53.402992 -318.016382)
		(end 52.229258 -318.016382)
		(width 0.12954)
		(layer "F.Cu")
		(net "I3C_SPD_DDRABCD_CPU1_LVC1_SDA")
	)
	(segment
		(start 4.994656 -317.435992)
		(end 4.994656 -306.664106)
		(width 0.12954)
		(layer "F.Cu")
		(net "I3C_SPD_DDRABCD_CPU1_LVC1_SDA")
	)
	(segment
		(start 36.787582 -317.587122)
		(end 35.685476 -317.587122)
		(width 0.12954)
		(layer "F.Cu")
		(net "I3C_SPD_DDRABCD_CPU1_LVC1_SDA")
	)
	(segment
		(start 22.103588 -318.016636)
		(end 21.674074 -317.587122)
		(width 0.12954)
		(layer "F.Cu")
		(net "I3C_SPD_DDRABCD_CPU1_LVC1_SDA")
	)
	(segment
		(start 13.369544 -169.065448)
		(end 17.14246 -165.292532)
		(width 0.12954)
		(layer "F.Cu")
		(net "I3C_SPD_DDRABCD_CPU1_LVC1_SDA")
	)
	(segment
		(start 10.246106 -317.587122)
		(end 9.816592 -318.016636)
		(width 0.12954)
		(layer "F.Cu")
		(net "I3C_SPD_DDRABCD_CPU1_LVC1_SDA")
	)
	(segment
		(start 74.86904 -140.632688)
		(end 75.748134 -140.632688)
		(width 0.12954)
		(layer "F.Cu")
		(net "I3C_SPD_DDRABCD_CPU1_LVC1_SDA")
	)
	(segment
		(start 18.4404 -162.15868)
		(end 18.4404 -150.856188)
		(width 0.12954)
		(layer "F.Cu")
		(net "I3C_SPD_DDRABCD_CPU1_LVC1_SDA")
	)
	(segment
		(start 53.403246 -318.016636)
		(end 53.402992 -318.016382)
		(width 0.12954)
		(layer "F.Cu")
		(net "I3C_SPD_DDRABCD_CPU1_LVC1_SDA")
	)
	(segment
		(start 59.048142 -318.016636)
		(end 58.618628 -317.587122)
		(width 0.12954)
		(layer "F.Cu")
		(net "I3C_SPD_DDRABCD_CPU1_LVC1_SDA")
	)
	(segment
		(start 51.799998 -317.587122)
		(end 50.773076 -317.587122)
		(width 0.12954)
		(layer "F.Cu")
		(net "I3C_SPD_DDRABCD_CPU1_LVC1_SDA")
	)
	(segment
		(start 20.597876 -317.587122)
		(end 18.983706 -317.587122)
		(width 0.1016)
		(layer "F.Cu")
		(net "I3C_SPD_DDRABCD_CPU1_LVC1_SDA")
	)
	(segment
		(start 11.439906 -317.587122)
		(end 10.246106 -317.587122)
		(width 0.12954)
		(layer "F.Cu")
		(net "I3C_SPD_DDRABCD_CPU1_LVC1_SDA")
	)
	(segment
		(start 4.91998 -175.283368)
		(end 11.1379 -169.065448)
		(width 0.12954)
		(layer "F.Cu")
		(net "I3C_SPD_DDRABCD_CPU1_LVC1_SDA")
	)
	(segment
		(start 23.228046 -318.016636)
		(end 22.103588 -318.016636)
		(width 0.12954)
		(layer "F.Cu")
		(net "I3C_SPD_DDRABCD_CPU1_LVC1_SDA")
	)
	(segment
		(start 76.881736 -141.76629)
		(end 76.881736 -142.187168)
		(width 0.12954)
		(layer "F.Cu")
		(net "I3C_SPD_DDRABCD_CPU1_LVC1_SDA")
	)
	(segment
		(start 37.217096 -318.016636)
		(end 36.787582 -317.587122)
		(width 0.12954)
		(layer "F.Cu")
		(net "I3C_SPD_DDRABCD_CPU1_LVC1_SDA")
	)
	(segment
		(start 41.364154 -317.587122)
		(end 41.615106 -317.587122)
		(width 0.12954)
		(layer "F.Cu")
		(net "I3C_SPD_DDRABCD_CPU1_LVC1_SDA")
	)
	(segment
		(start 43.90771 -317.587122)
		(end 44.337224 -318.016636)
		(width 0.12954)
		(layer "F.Cu")
		(net "I3C_SPD_DDRABCD_CPU1_LVC1_SDA")
	)
	(segment
		(start 17.743678 -317.587122)
		(end 17.314164 -318.016636)
		(width 0.12954)
		(layer "F.Cu")
		(net "I3C_SPD_DDRABCD_CPU1_LVC1_SDA")
	)
	(segment
		(start 17.14246 -165.292532)
		(end 18.4404 -162.15868)
		(width 0.12954)
		(layer "F.Cu")
		(net "I3C_SPD_DDRABCD_CPU1_LVC1_SDA")
	)
	(segment
		(start 4.91998 -191.333882)
		(end 4.91998 -175.283368)
		(width 0.12954)
		(layer "F.Cu")
		(net "I3C_SPD_DDRABCD_CPU1_LVC1_SDA")
	)
	(segment
		(start 50.773076 -317.587122)
		(end 49.158906 -317.587122)
		(width 0.1016)
		(layer "F.Cu")
		(net "I3C_SPD_DDRABCD_CPU1_LVC1_SDA")
	)
	(segment
		(start 41.23182 -317.454788)
		(end 41.364154 -317.587122)
		(width 0.12954)
		(layer "F.Cu")
		(net "I3C_SPD_DDRABCD_CPU1_LVC1_SDA")
	)
	(segment
		(start 24.954738 -317.587122)
		(end 24.525224 -318.016636)
		(width 0.12954)
		(layer "F.Cu")
		(net "I3C_SPD_DDRABCD_CPU1_LVC1_SDA")
	)
	(segment
		(start 5.5753 -318.016636)
		(end 4.994656 -317.435992)
		(width 0.12954)
		(layer "F.Cu")
		(net "I3C_SPD_DDRABCD_CPU1_LVC1_SDA")
	)
	(segment
		(start 56.702706 -317.587122)
		(end 55.587138 -317.587122)
		(width 0.12954)
		(layer "F.Cu")
		(net "I3C_SPD_DDRABCD_CPU1_LVC1_SDA")
	)
	(segment
		(start 21.674074 -317.587122)
		(end 20.597876 -317.587122)
		(width 0.12954)
		(layer "F.Cu")
		(net "I3C_SPD_DDRABCD_CPU1_LVC1_SDA")
	)
	(segment
		(start 58.618628 -317.587122)
		(end 58.316876 -317.587122)
		(width 0.12954)
		(layer "F.Cu")
		(net "I3C_SPD_DDRABCD_CPU1_LVC1_SDA")
	)
	(segment
		(start 13.054076 -317.587122)
		(end 11.439906 -317.587122)
		(width 0.1016)
		(layer "F.Cu")
		(net "I3C_SPD_DDRABCD_CPU1_LVC1_SDA")
	)
	(segment
		(start 18.983706 -317.587122)
		(end 17.743678 -317.587122)
		(width 0.12954)
		(layer "F.Cu")
		(net "I3C_SPD_DDRABCD_CPU1_LVC1_SDA")
	)
	(segment
		(start 38.315646 -318.016636)
		(end 39.625524 -318.016636)
		(width 0.12954)
		(layer "F.Cu")
		(net "I3C_SPD_DDRABCD_CPU1_LVC1_SDA")
	)
	(segment
		(start 55.587138 -317.587122)
		(end 55.157878 -318.016382)
		(width 0.12954)
		(layer "F.Cu")
		(net "I3C_SPD_DDRABCD_CPU1_LVC1_SDA")
	)
	(segment
		(start 15.684246 -318.016636)
		(end 14.06017 -318.016636)
		(width 0.12954)
		(layer "F.Cu")
		(net "I3C_SPD_DDRABCD_CPU1_LVC1_SDA")
	)
	(segment
		(start 26.527506 -317.587122)
		(end 24.954738 -317.587122)
		(width 0.12954)
		(layer "F.Cu")
		(net "I3C_SPD_DDRABCD_CPU1_LVC1_SDA")
	)
	(segment
		(start 28.6639 -140.632688)
		(end 74.86904 -140.632688)
		(width 0.12954)
		(layer "F.Cu")
		(net "I3C_SPD_DDRABCD_CPU1_LVC1_SDA")
	)
	(segment
		(start 75.748134 -140.632688)
		(end 76.881736 -141.76629)
		(width 0.12954)
		(layer "F.Cu")
		(net "I3C_SPD_DDRABCD_CPU1_LVC1_SDA")
	)
	(segment
		(start 24.525224 -318.016636)
		(end 23.228046 -318.016636)
		(width 0.12954)
		(layer "F.Cu")
		(net "I3C_SPD_DDRABCD_CPU1_LVC1_SDA")
	)
	(segment
		(start 29.259784 -318.016636)
		(end 28.83027 -317.587122)
		(width 0.12954)
		(layer "F.Cu")
		(net "I3C_SPD_DDRABCD_CPU1_LVC1_SDA")
	)
	(segment
		(start 5.715762 -305.943)
		(end 5.715762 -198.02475)
		(width 0.12954)
		(layer "F.Cu")
		(net "I3C_SPD_DDRABCD_CPU1_LVC1_SDA")
	)
	(via
		(at 74.86904 -140.632688)
		(size 0.762)
		(drill 0.381)
		(layers "F.Cu" "B.Cu")
		(net "I3C_SPD_DDRABCD_CPU1_LVC1_SDA")
	)
	(segment
		(start 74.992738 -146.13636)
		(end 76.446634 -144.682464)
		(width 0.12954)
		(layer "F.Cu")
		(net "I3C_SPD_DDRABCD_CPU1_LVC1_SCL")
	)
	(segment
		(start 5.719318 -316.135766)
		(end 5.8547 -316.271148)
		(width 0.12954)
		(layer "F.Cu")
		(net "I3C_SPD_DDRABCD_CPU1_LVC1_SCL")
	)
	(segment
		(start 74.410062 -141.35735)
		(end 28.964128 -141.35735)
		(width 0.12954)
		(layer "F.Cu")
		(net "I3C_SPD_DDRABCD_CPU1_LVC1_SCL")
	)
	(segment
		(start 19.132804 -162.2552)
		(end 17.70888 -165.693344)
		(width 0.12954)
		(layer "F.Cu")
		(net "I3C_SPD_DDRABCD_CPU1_LVC1_SCL")
	)
	(segment
		(start 19.132804 -151.188674)
		(end 19.132804 -162.2552)
		(width 0.12954)
		(layer "F.Cu")
		(net "I3C_SPD_DDRABCD_CPU1_LVC1_SCL")
	)
	(segment
		(start 74.992738 -152.321006)
		(end 74.992738 -146.13636)
		(width 0.12954)
		(layer "F.Cu")
		(net "I3C_SPD_DDRABCD_CPU1_LVC1_SCL")
	)
	(segment
		(start 5.8547 -316.271148)
		(end 6.99008 -316.271148)
		(width 0.12954)
		(layer "F.Cu")
		(net "I3C_SPD_DDRABCD_CPU1_LVC1_SCL")
	)
	(segment
		(start 5.59562 -175.632618)
		(end 5.59562 -191.59601)
		(width 0.12954)
		(layer "F.Cu")
		(net "I3C_SPD_DDRABCD_CPU1_LVC1_SCL")
	)
	(segment
		(start 5.719318 -306.964334)
		(end 5.719318 -316.135766)
		(width 0.12954)
		(layer "F.Cu")
		(net "I3C_SPD_DDRABCD_CPU1_LVC1_SCL")
	)
	(segment
		(start 11.07567 -170.152568)
		(end 5.59562 -175.632618)
		(width 0.12954)
		(layer "F.Cu")
		(net "I3C_SPD_DDRABCD_CPU1_LVC1_SCL")
	)
	(segment
		(start 3.90906 -195.232274)
		(end 6.440424 -197.763638)
		(width 0.12954)
		(layer "F.Cu")
		(net "I3C_SPD_DDRABCD_CPU1_LVC1_SCL")
	)
	(segment
		(start 13.249656 -170.152568)
		(end 11.07567 -170.152568)
		(width 0.12954)
		(layer "F.Cu")
		(net "I3C_SPD_DDRABCD_CPU1_LVC1_SCL")
	)
	(segment
		(start 76.446634 -143.393922)
		(end 74.410062 -141.35735)
		(width 0.12954)
		(layer "F.Cu")
		(net "I3C_SPD_DDRABCD_CPU1_LVC1_SCL")
	)
	(segment
		(start 17.70888 -165.693344)
		(end 13.249656 -170.152568)
		(width 0.12954)
		(layer "F.Cu")
		(net "I3C_SPD_DDRABCD_CPU1_LVC1_SCL")
	)
	(segment
		(start 77.760576 -152.96515)
		(end 75.636882 -152.96515)
		(width 0.12954)
		(layer "F.Cu")
		(net "I3C_SPD_DDRABCD_CPU1_LVC1_SCL")
	)
	(segment
		(start 6.440424 -306.243228)
		(end 5.719318 -306.964334)
		(width 0.12954)
		(layer "F.Cu")
		(net "I3C_SPD_DDRABCD_CPU1_LVC1_SCL")
	)
	(segment
		(start 6.440424 -197.763638)
		(end 6.440424 -306.243228)
		(width 0.12954)
		(layer "F.Cu")
		(net "I3C_SPD_DDRABCD_CPU1_LVC1_SCL")
	)
	(segment
		(start 28.964128 -141.35735)
		(end 19.132804 -151.188674)
		(width 0.12954)
		(layer "F.Cu")
		(net "I3C_SPD_DDRABCD_CPU1_LVC1_SCL")
	)
	(segment
		(start 75.636882 -152.96515)
		(end 74.992738 -152.321006)
		(width 0.12954)
		(layer "F.Cu")
		(net "I3C_SPD_DDRABCD_CPU1_LVC1_SCL")
	)
	(segment
		(start 3.90906 -193.28257)
		(end 3.90906 -195.232274)
		(width 0.12954)
		(layer "F.Cu")
		(net "I3C_SPD_DDRABCD_CPU1_LVC1_SCL")
	)
	(segment
		(start 5.59562 -191.59601)
		(end 3.90906 -193.28257)
		(width 0.12954)
		(layer "F.Cu")
		(net "I3C_SPD_DDRABCD_CPU1_LVC1_SCL")
	)
	(segment
		(start 77.760576 -152.226772)
		(end 77.760576 -152.96515)
		(width 0.12954)
		(layer "F.Cu")
		(net "I3C_SPD_DDRABCD_CPU1_LVC1_SCL")
	)
	(segment
		(start 76.446634 -144.682464)
		(end 76.446634 -143.393922)
		(width 0.12954)
		(layer "F.Cu")
		(net "I3C_SPD_DDRABCD_CPU1_LVC1_SCL")
	)
	(via
		(at 33.002982 -314.569094)
		(size 0.4572)
		(drill 0.2032)
		(layers "F.Cu" "B.Cu")
		(net "I3C_SPD_DDRABCD_CPU1_LVC1_SCL")
	)
	(via
		(at 6.99008 -316.271148)
		(size 0.508)
		(drill 0.254)
		(layers "F.Cu" "B.Cu")
		(net "I3C_SPD_DDRABCD_CPU1_LVC1_SCL")
	)
	(via
		(at 77.760576 -152.96515)
		(size 0.508)
		(drill 0.254)
		(layers "F.Cu" "B.Cu")
		(net "I3C_SPD_DDRABCD_CPU1_LVC1_SCL")
	)
	(via
		(at 40.67302 -317.969138)
		(size 0.4572)
		(drill 0.2032)
		(layers "F.Cu" "B.Cu")
		(net "I3C_SPD_DDRABCD_CPU1_LVC1_SCL")
	)
	(segment
		(start 23.145242 -315.96584)
		(end 23.019004 -316.092078)
		(width 0.12954)
		(layer "B.Cu")
		(net "I3C_SPD_DDRABCD_CPU1_LVC1_SCL")
	)
	(segment
		(start 20.262596 -315.628782)
		(end 18.42008 -315.628782)
		(width 0.12954)
		(layer "B.Cu")
		(net "I3C_SPD_DDRABCD_CPU1_LVC1_SCL")
	)
	(segment
		(start 29.565092 -316.350396)
		(end 28.880308 -315.665612)
		(width 0.12954)
		(layer "B.Cu")
		(net "I3C_SPD_DDRABCD_CPU1_LVC1_SCL")
	)
	(segment
		(start 8.38327 -317.42507)
		(end 8.38327 -318.04483)
		(width 0.12954)
		(layer "B.Cu")
		(net "I3C_SPD_DDRABCD_CPU1_LVC1_SCL")
	)
	(segment
		(start 30.523434 -316.350396)
		(end 29.565092 -316.350396)
		(width 0.12954)
		(layer "B.Cu")
		(net "I3C_SPD_DDRABCD_CPU1_LVC1_SCL")
	)
	(segment
		(start 40.71239 -317.969138)
		(end 41.514776 -317.166752)
		(width 0.12954)
		(layer "B.Cu")
		(net "I3C_SPD_DDRABCD_CPU1_LVC1_SCL")
	)
	(segment
		(start 53.144166 -316.115954)
		(end 53.144166 -315.218572)
		(width 0.12954)
		(layer "B.Cu")
		(net "I3C_SPD_DDRABCD_CPU1_LVC1_SCL")
	)
	(segment
		(start 33.603692 -315.557662)
		(end 32.695388 -315.557662)
		(width 0.12954)
		(layer "B.Cu")
		(net "I3C_SPD_DDRABCD_CPU1_LVC1_SCL")
	)
	(segment
		(start 8.38327 -318.04483)
		(end 8.553196 -318.214756)
		(width 0.12954)
		(layer "B.Cu")
		(net "I3C_SPD_DDRABCD_CPU1_LVC1_SCL")
	)
	(segment
		(start 44.794932 -314.6298)
		(end 46.291754 -314.6298)
		(width 0.12954)
		(layer "B.Cu")
		(net "I3C_SPD_DDRABCD_CPU1_LVC1_SCL")
	)
	(segment
		(start 32.36595 -315.8871)
		(end 31.481522 -315.8871)
		(width 0.12954)
		(layer "B.Cu")
		(net "I3C_SPD_DDRABCD_CPU1_LVC1_SCL")
	)
	(segment
		(start 32.695388 -315.557662)
		(end 32.36595 -315.8871)
		(width 0.12954)
		(layer "B.Cu")
		(net "I3C_SPD_DDRABCD_CPU1_LVC1_SCL")
	)
	(segment
		(start 44.16171 -315.023754)
		(end 44.400978 -315.023754)
		(width 0.12954)
		(layer "B.Cu")
		(net "I3C_SPD_DDRABCD_CPU1_LVC1_SCL")
	)
	(segment
		(start 41.514776 -317.166752)
		(end 41.658032 -317.166752)
		(width 0.12954)
		(layer "B.Cu")
		(net "I3C_SPD_DDRABCD_CPU1_LVC1_SCL")
	)
	(segment
		(start 31.323534 -317.3984)
		(end 31.184596 -317.537338)
		(width 0.12954)
		(layer "B.Cu")
		(net "I3C_SPD_DDRABCD_CPU1_LVC1_SCL")
	)
	(segment
		(start 46.706282 -315.044328)
		(end 48.02886 -315.044328)
		(width 0.12954)
		(layer "B.Cu")
		(net "I3C_SPD_DDRABCD_CPU1_LVC1_SCL")
	)
	(segment
		(start 23.879302 -316.22365)
		(end 23.621492 -315.96584)
		(width 0.12954)
		(layer "B.Cu")
		(net "I3C_SPD_DDRABCD_CPU1_LVC1_SCL")
	)
	(segment
		(start 25.332436 -315.665612)
		(end 24.774398 -316.22365)
		(width 0.12954)
		(layer "B.Cu")
		(net "I3C_SPD_DDRABCD_CPU1_LVC1_SCL")
	)
	(segment
		(start 30.860238 -317.302388)
		(end 30.860238 -316.6872)
		(width 0.12954)
		(layer "B.Cu")
		(net "I3C_SPD_DDRABCD_CPU1_LVC1_SCL")
	)
	(segment
		(start 23.621492 -315.96584)
		(end 23.145242 -315.96584)
		(width 0.12954)
		(layer "B.Cu")
		(net "I3C_SPD_DDRABCD_CPU1_LVC1_SCL")
	)
	(segment
		(start 41.658032 -317.166752)
		(end 43.80103 -315.023754)
		(width 0.12954)
		(layer "B.Cu")
		(net "I3C_SPD_DDRABCD_CPU1_LVC1_SCL")
	)
	(segment
		(start 9.10717 -316.171834)
		(end 8.76427 -316.514734)
		(width 0.12954)
		(layer "B.Cu")
		(net "I3C_SPD_DDRABCD_CPU1_LVC1_SCL")
	)
	(segment
		(start 55.950612 -315.539882)
		(end 57.48147 -315.539882)
		(width 0.12954)
		(layer "B.Cu")
		(net "I3C_SPD_DDRABCD_CPU1_LVC1_SCL")
	)
	(segment
		(start 13.539978 -315.592714)
		(end 10.791698 -315.592714)
		(width 0.12954)
		(layer "B.Cu")
		(net "I3C_SPD_DDRABCD_CPU1_LVC1_SCL")
	)
	(segment
		(start 50.644552 -315.8871)
		(end 51.843686 -315.8871)
		(width 0.12954)
		(layer "B.Cu")
		(net "I3C_SPD_DDRABCD_CPU1_LVC1_SCL")
	)
	(segment
		(start 16.116554 -316.201044)
		(end 15.69085 -316.201044)
		(width 0.12954)
		(layer "B.Cu")
		(net "I3C_SPD_DDRABCD_CPU1_LVC1_SCL")
	)
	(segment
		(start 14.150594 -316.20333)
		(end 13.539978 -315.592714)
		(width 0.12954)
		(layer "B.Cu")
		(net "I3C_SPD_DDRABCD_CPU1_LVC1_SCL")
	)
	(segment
		(start 31.481522 -315.8871)
		(end 31.323534 -316.045088)
		(width 0.12954)
		(layer "B.Cu")
		(net "I3C_SPD_DDRABCD_CPU1_LVC1_SCL")
	)
	(segment
		(start 55.142384 -314.731654)
		(end 55.950612 -315.539882)
		(width 0.12954)
		(layer "B.Cu")
		(net "I3C_SPD_DDRABCD_CPU1_LVC1_SCL")
	)
	(segment
		(start 8.553196 -318.214756)
		(end 8.553196 -318.25311)
		(width 0.12954)
		(layer "B.Cu")
		(net "I3C_SPD_DDRABCD_CPU1_LVC1_SCL")
	)
	(segment
		(start 23.019004 -316.092078)
		(end 21.71573 -316.092078)
		(width 0.12954)
		(layer "B.Cu")
		(net "I3C_SPD_DDRABCD_CPU1_LVC1_SCL")
	)
	(segment
		(start 48.38827 -315.403738)
		(end 50.16119 -315.403738)
		(width 0.12954)
		(layer "B.Cu")
		(net "I3C_SPD_DDRABCD_CPU1_LVC1_SCL")
	)
	(segment
		(start 51.843686 -315.8871)
		(end 52.228496 -316.27191)
		(width 0.12954)
		(layer "B.Cu")
		(net "I3C_SPD_DDRABCD_CPU1_LVC1_SCL")
	)
	(segment
		(start 18.42008 -315.628782)
		(end 18.152618 -315.896244)
		(width 0.12954)
		(layer "B.Cu")
		(net "I3C_SPD_DDRABCD_CPU1_LVC1_SCL")
	)
	(segment
		(start 16.421354 -315.896244)
		(end 16.116554 -316.201044)
		(width 0.12954)
		(layer "B.Cu")
		(net "I3C_SPD_DDRABCD_CPU1_LVC1_SCL")
	)
	(segment
		(start 53.631084 -314.731654)
		(end 55.142384 -314.731654)
		(width 0.12954)
		(layer "B.Cu")
		(net "I3C_SPD_DDRABCD_CPU1_LVC1_SCL")
	)
	(segment
		(start 40.67302 -317.969138)
		(end 40.71239 -317.969138)
		(width 0.12954)
		(layer "B.Cu")
		(net "I3C_SPD_DDRABCD_CPU1_LVC1_SCL")
	)
	(segment
		(start 15.69085 -316.201044)
		(end 15.688564 -316.20333)
		(width 0.12954)
		(layer "B.Cu")
		(net "I3C_SPD_DDRABCD_CPU1_LVC1_SCL")
	)
	(segment
		(start 20.530058 -315.896244)
		(end 20.262596 -315.628782)
		(width 0.12954)
		(layer "B.Cu")
		(net "I3C_SPD_DDRABCD_CPU1_LVC1_SCL")
	)
	(segment
		(start 15.688564 -316.20333)
		(end 14.150594 -316.20333)
		(width 0.12954)
		(layer "B.Cu")
		(net "I3C_SPD_DDRABCD_CPU1_LVC1_SCL")
	)
	(segment
		(start 53.046376 -316.213744)
		(end 53.144166 -316.115954)
		(width 0.12954)
		(layer "B.Cu")
		(net "I3C_SPD_DDRABCD_CPU1_LVC1_SCL")
	)
	(segment
		(start 43.80103 -315.023754)
		(end 44.16171 -315.023754)
		(width 0.12954)
		(layer "B.Cu")
		(net "I3C_SPD_DDRABCD_CPU1_LVC1_SCL")
	)
	(segment
		(start 10.212578 -316.171834)
		(end 9.10717 -316.171834)
		(width 0.12954)
		(layer "B.Cu")
		(net "I3C_SPD_DDRABCD_CPU1_LVC1_SCL")
	)
	(segment
		(start 50.16119 -315.403738)
		(end 50.644552 -315.8871)
		(width 0.12954)
		(layer "B.Cu")
		(net "I3C_SPD_DDRABCD_CPU1_LVC1_SCL")
	)
	(segment
		(start 52.228496 -316.27191)
		(end 52.98821 -316.27191)
		(width 0.12954)
		(layer "B.Cu")
		(net "I3C_SPD_DDRABCD_CPU1_LVC1_SCL")
	)
	(segment
		(start 31.184596 -317.626746)
		(end 30.860238 -317.302388)
		(width 0.12954)
		(layer "B.Cu")
		(net "I3C_SPD_DDRABCD_CPU1_LVC1_SCL")
	)
	(segment
		(start 31.323534 -316.045088)
		(end 31.323534 -317.3984)
		(width 0.12954)
		(layer "B.Cu")
		(net "I3C_SPD_DDRABCD_CPU1_LVC1_SCL")
	)
	(segment
		(start 8.76427 -318.111124)
		(end 8.622284 -318.25311)
		(width 0.12954)
		(layer "B.Cu")
		(net "I3C_SPD_DDRABCD_CPU1_LVC1_SCL")
	)
	(segment
		(start 8.622284 -318.25311)
		(end 8.553196 -318.25311)
		(width 0.12954)
		(layer "B.Cu")
		(net "I3C_SPD_DDRABCD_CPU1_LVC1_SCL")
	)
	(segment
		(start 33.603692 -315.292486)
		(end 33.603692 -315.557662)
		(width 0.12954)
		(layer "B.Cu")
		(net "I3C_SPD_DDRABCD_CPU1_LVC1_SCL")
	)
	(segment
		(start 24.774398 -316.22365)
		(end 23.879302 -316.22365)
		(width 0.12954)
		(layer "B.Cu")
		(net "I3C_SPD_DDRABCD_CPU1_LVC1_SCL")
	)
	(segment
		(start 52.98821 -316.27191)
		(end 53.046376 -316.213744)
		(width 0.12954)
		(layer "B.Cu")
		(net "I3C_SPD_DDRABCD_CPU1_LVC1_SCL")
	)
	(segment
		(start 53.144166 -315.218572)
		(end 53.631084 -314.731654)
		(width 0.12954)
		(layer "B.Cu")
		(net "I3C_SPD_DDRABCD_CPU1_LVC1_SCL")
	)
	(segment
		(start 8.76427 -316.514734)
		(end 8.76427 -318.111124)
		(width 0.12954)
		(layer "B.Cu")
		(net "I3C_SPD_DDRABCD_CPU1_LVC1_SCL")
	)
	(segment
		(start 44.400978 -315.023754)
		(end 44.794932 -314.6298)
		(width 0.12954)
		(layer "B.Cu")
		(net "I3C_SPD_DDRABCD_CPU1_LVC1_SCL")
	)
	(segment
		(start 33.002982 -314.691776)
		(end 33.603692 -315.292486)
		(width 0.12954)
		(layer "B.Cu")
		(net "I3C_SPD_DDRABCD_CPU1_LVC1_SCL")
	)
	(segment
		(start 30.860238 -316.6872)
		(end 30.523434 -316.350396)
		(width 0.12954)
		(layer "B.Cu")
		(net "I3C_SPD_DDRABCD_CPU1_LVC1_SCL")
	)
	(segment
		(start 33.002982 -314.569094)
		(end 33.002982 -314.691776)
		(width 0.12954)
		(layer "B.Cu")
		(net "I3C_SPD_DDRABCD_CPU1_LVC1_SCL")
	)
	(segment
		(start 21.71573 -316.092078)
		(end 21.519896 -315.896244)
		(width 0.12954)
		(layer "B.Cu")
		(net "I3C_SPD_DDRABCD_CPU1_LVC1_SCL")
	)
	(segment
		(start 21.519896 -315.896244)
		(end 20.530058 -315.896244)
		(width 0.12954)
		(layer "B.Cu")
		(net "I3C_SPD_DDRABCD_CPU1_LVC1_SCL")
	)
	(segment
		(start 28.880308 -315.665612)
		(end 25.332436 -315.665612)
		(width 0.12954)
		(layer "B.Cu")
		(net "I3C_SPD_DDRABCD_CPU1_LVC1_SCL")
	)
	(segment
		(start 18.152618 -315.896244)
		(end 16.421354 -315.896244)
		(width 0.12954)
		(layer "B.Cu")
		(net "I3C_SPD_DDRABCD_CPU1_LVC1_SCL")
	)
	(segment
		(start 46.291754 -314.6298)
		(end 46.706282 -315.044328)
		(width 0.12954)
		(layer "B.Cu")
		(net "I3C_SPD_DDRABCD_CPU1_LVC1_SCL")
	)
	(segment
		(start 31.184596 -317.537338)
		(end 31.184596 -317.626746)
		(width 0.12954)
		(layer "B.Cu")
		(net "I3C_SPD_DDRABCD_CPU1_LVC1_SCL")
	)
	(segment
		(start 10.791698 -315.592714)
		(end 10.212578 -316.171834)
		(width 0.12954)
		(layer "B.Cu")
		(net "I3C_SPD_DDRABCD_CPU1_LVC1_SCL")
	)
	(segment
		(start 6.99008 -316.271148)
		(end 7.229348 -316.271148)
		(width 0.12954)
		(layer "B.Cu")
		(net "I3C_SPD_DDRABCD_CPU1_LVC1_SCL")
	)
	(segment
		(start 7.229348 -316.271148)
		(end 8.38327 -317.42507)
		(width 0.12954)
		(layer "B.Cu")
		(net "I3C_SPD_DDRABCD_CPU1_LVC1_SCL")
	)
	(segment
		(start 48.02886 -315.044328)
		(end 48.38827 -315.403738)
		(width 0.12954)
		(layer "B.Cu")
		(net "I3C_SPD_DDRABCD_CPU1_LVC1_SCL")
	)
	(segment
		(start 40.67302 -317.969138)
		(end 40.63365 -317.969138)
		(width 0.127)
		(layer "In13.Cu")
		(net "I3C_SPD_DDRABCD_CPU1_LVC1_SCL")
	)
	(segment
		(start 34.809176 -317.1825)
		(end 33.398206 -317.1825)
		(width 0.127)
		(layer "In13.Cu")
		(net "I3C_SPD_DDRABCD_CPU1_LVC1_SCL")
	)
	(segment
		(start 40.63365 -317.969138)
		(end 40.583866 -317.919354)
		(width 0.127)
		(layer "In13.Cu")
		(net "I3C_SPD_DDRABCD_CPU1_LVC1_SCL")
	)
	(segment
		(start 33.002982 -316.787276)
		(end 33.002982 -314.569094)
		(width 0.127)
		(layer "In13.Cu")
		(net "I3C_SPD_DDRABCD_CPU1_LVC1_SCL")
	)
	(segment
		(start 40.583866 -317.919354)
		(end 35.54603 -317.919354)
		(width 0.127)
		(layer "In13.Cu")
		(net "I3C_SPD_DDRABCD_CPU1_LVC1_SCL")
	)
	(segment
		(start 35.54603 -317.919354)
		(end 34.809176 -317.1825)
		(width 0.127)
		(layer "In13.Cu")
		(net "I3C_SPD_DDRABCD_CPU1_LVC1_SCL")
	)
	(segment
		(start 33.398206 -317.1825)
		(end 33.002982 -316.787276)
		(width 0.127)
		(layer "In13.Cu")
		(net "I3C_SPD_DDRABCD_CPU1_LVC1_SCL")
	)
	(segment
		(start 76.999338 -146.090132)
		(end 78.009496 -146.090132)
		(width 0.12954)
		(layer "F.Cu")
		(net "I3C_SPD_DDRABCD_CPU1_LVC1_R_SDA")
	)
	(segment
		(start 77.989938 -142.987268)
		(end 77.966824 -142.987268)
		(width 0.12954)
		(layer "F.Cu")
		(net "I3C_SPD_DDRABCD_CPU1_LVC1_R_SDA")
	)
	(segment
		(start 77.966824 -142.987268)
		(end 76.881736 -142.987268)
		(width 0.12954)
		(layer "F.Cu")
		(net "I3C_SPD_DDRABCD_CPU1_LVC1_R_SDA")
	)
	(segment
		(start 78.631542 -143.628872)
		(end 77.989938 -142.987268)
		(width 0.12954)
		(layer "F.Cu")
		(net "I3C_SPD_DDRABCD_CPU1_LVC1_R_SDA")
	)
	(segment
		(start 78.631542 -144.196816)
		(end 78.631542 -143.628872)
		(width 0.12954)
		(layer "F.Cu")
		(net "I3C_SPD_DDRABCD_CPU1_LVC1_R_SDA")
	)
	(segment
		(start 78.009496 -146.090132)
		(end 78.631542 -145.468086)
		(width 0.12954)
		(layer "F.Cu")
		(net "I3C_SPD_DDRABCD_CPU1_LVC1_R_SDA")
	)
	(segment
		(start 78.631542 -145.468086)
		(end 78.631542 -144.196816)
		(width 0.12954)
		(layer "F.Cu")
		(net "I3C_SPD_DDRABCD_CPU1_LVC1_R_SDA")
	)
	(via
		(at 78.631542 -144.196816)
		(size 0.762)
		(drill 0.381)
		(layers "F.Cu" "B.Cu")
		(net "I3C_SPD_DDRABCD_CPU1_LVC1_R_SDA")
	)
	(segment
		(start 79.249778 -149.52345)
		(end 79.249778 -150.52167)
		(width 0.12954)
		(layer "F.Cu")
		(net "I3C_SPD_DDRABCD_CPU1_LVC1_R_SCL")
	)
	(segment
		(start 79.249778 -148.30171)
		(end 79.249778 -149.52345)
		(width 0.12954)
		(layer "F.Cu")
		(net "I3C_SPD_DDRABCD_CPU1_LVC1_R_SCL")
	)
	(segment
		(start 76.999338 -147.995132)
		(end 78.9432 -147.995132)
		(width 0.12954)
		(layer "F.Cu")
		(net "I3C_SPD_DDRABCD_CPU1_LVC1_R_SCL")
	)
	(segment
		(start 78.560676 -151.210772)
		(end 78.560676 -152.226772)
		(width 0.12954)
		(layer "F.Cu")
		(net "I3C_SPD_DDRABCD_CPU1_LVC1_R_SCL")
	)
	(segment
		(start 79.249778 -150.52167)
		(end 78.560676 -151.210772)
		(width 0.12954)
		(layer "F.Cu")
		(net "I3C_SPD_DDRABCD_CPU1_LVC1_R_SCL")
	)
	(segment
		(start 78.9432 -147.995132)
		(end 79.249778 -148.30171)
		(width 0.12954)
		(layer "F.Cu")
		(net "I3C_SPD_DDRABCD_CPU1_LVC1_R_SCL")
	)
	(via
		(at 79.249778 -149.52345)
		(size 0.508)
		(drill 0.254)
		(layers "F.Cu" "B.Cu")
		(net "I3C_SPD_DDRABCD_CPU1_LVC1_R_SCL")
	)
	(segment
		(start 76.999338 -146.725132)
		(end 78.228698 -146.725132)
		(width 0.12954)
		(layer "F.Cu")
		(net "I3C_SPD_DDRABCD_CPU1_BMC_SDA")
	)
	(via
		(at 78.228698 -146.725132)
		(size 0.508)
		(drill 0.254)
		(layers "F.Cu" "B.Cu")
		(net "I3C_SPD_DDRABCD_CPU1_BMC_SDA")
	)
	(via
		(at 185.240422 -14.747748)
		(size 0.508)
		(drill 0.254)
		(layers "F.Cu" "B.Cu")
		(net "I3C_SPD_DDRABCD_CPU1_BMC_SDA")
	)
	(segment
		(start 185.240422 -14.00048)
		(end 185.240422 -14.747748)
		(width 0.12954)
		(layer "B.Cu")
		(net "I3C_SPD_DDRABCD_CPU1_BMC_SDA")
	)
	(segment
		(start 99.897184 -41.760394)
		(end 98.867722 -42.18686)
		(width 0.127)
		(layer "In4.Cu")
		(net "I3C_SPD_DDRABCD_CPU1_BMC_SDA")
	)
	(segment
		(start 184.778142 -14.285468)
		(end 183.39816 -14.285468)
		(width 0.127)
		(layer "In4.Cu")
		(net "I3C_SPD_DDRABCD_CPU1_BMC_SDA")
	)
	(segment
		(start 55.75808 -62.716918)
		(end 55.75808 -78.055978)
		(width 0.127)
		(layer "In4.Cu")
		(net "I3C_SPD_DDRABCD_CPU1_BMC_SDA")
	)
	(segment
		(start 155.281376 -14.389608)
		(end 155.154376 -14.262608)
		(width 0.127)
		(layer "In4.Cu")
		(net "I3C_SPD_DDRABCD_CPU1_BMC_SDA")
	)
	(segment
		(start 87.879936 -44.35475)
		(end 82.666078 -49.568608)
		(width 0.127)
		(layer "In4.Cu")
		(net "I3C_SPD_DDRABCD_CPU1_BMC_SDA")
	)
	(segment
		(start 155.789376 -13.790168)
		(end 155.789376 -14.262608)
		(width 0.127)
		(layer "In4.Cu")
		(net "I3C_SPD_DDRABCD_CPU1_BMC_SDA")
	)
	(segment
		(start 181.348888 -12.769088)
		(end 177.924968 -9.345168)
		(width 0.127)
		(layer "In4.Cu")
		(net "I3C_SPD_DDRABCD_CPU1_BMC_SDA")
	)
	(segment
		(start 98.867722 -42.18686)
		(end 92.18422 -42.18686)
		(width 0.127)
		(layer "In4.Cu")
		(net "I3C_SPD_DDRABCD_CPU1_BMC_SDA")
	)
	(segment
		(start 135.21436 -21.326348)
		(end 128.9812 -21.326348)
		(width 0.127)
		(layer "In4.Cu")
		(net "I3C_SPD_DDRABCD_CPU1_BMC_SDA")
	)
	(segment
		(start 154.177492 -13.663168)
		(end 146.514312 -21.326348)
		(width 0.127)
		(layer "In4.Cu")
		(net "I3C_SPD_DDRABCD_CPU1_BMC_SDA")
	)
	(segment
		(start 71.70293 -59.878468)
		(end 58.59653 -59.878468)
		(width 0.127)
		(layer "In4.Cu")
		(net "I3C_SPD_DDRABCD_CPU1_BMC_SDA")
	)
	(segment
		(start 73.475088 -95.772986)
		(end 73.475088 -129.733294)
		(width 0.127)
		(layer "In4.Cu")
		(net "I3C_SPD_DDRABCD_CPU1_BMC_SDA")
	)
	(segment
		(start 155.154376 -13.790168)
		(end 155.027376 -13.663168)
		(width 0.127)
		(layer "In4.Cu")
		(net "I3C_SPD_DDRABCD_CPU1_BMC_SDA")
	)
	(segment
		(start 82.666078 -49.568608)
		(end 82.01279 -49.568608)
		(width 0.127)
		(layer "In4.Cu")
		(net "I3C_SPD_DDRABCD_CPU1_BMC_SDA")
	)
	(segment
		(start 125.901704 -25.618694)
		(end 116.515134 -35.005264)
		(width 0.127)
		(layer "In4.Cu")
		(net "I3C_SPD_DDRABCD_CPU1_BMC_SDA")
	)
	(segment
		(start 185.240422 -14.747748)
		(end 184.778142 -14.285468)
		(width 0.127)
		(layer "In4.Cu")
		(net "I3C_SPD_DDRABCD_CPU1_BMC_SDA")
	)
	(segment
		(start 142.958312 -21.326348)
		(end 141.06398 -23.22068)
		(width 0.127)
		(layer "In4.Cu")
		(net "I3C_SPD_DDRABCD_CPU1_BMC_SDA")
	)
	(segment
		(start 167.54348 -9.751568)
		(end 163.52012 -9.751568)
		(width 0.127)
		(layer "In4.Cu")
		(net "I3C_SPD_DDRABCD_CPU1_BMC_SDA")
	)
	(segment
		(start 89.396062 -43.341798)
		(end 87.879936 -44.35475)
		(width 0.127)
		(layer "In4.Cu")
		(net "I3C_SPD_DDRABCD_CPU1_BMC_SDA")
	)
	(segment
		(start 137.108692 -23.22068)
		(end 135.21436 -21.326348)
		(width 0.127)
		(layer "In4.Cu")
		(net "I3C_SPD_DDRABCD_CPU1_BMC_SDA")
	)
	(segment
		(start 177.924968 -9.345168)
		(end 167.94988 -9.345168)
		(width 0.127)
		(layer "In4.Cu")
		(net "I3C_SPD_DDRABCD_CPU1_BMC_SDA")
	)
	(segment
		(start 167.94988 -9.345168)
		(end 167.54348 -9.751568)
		(width 0.127)
		(layer "In4.Cu")
		(net "I3C_SPD_DDRABCD_CPU1_BMC_SDA")
	)
	(segment
		(start 155.916376 -13.663168)
		(end 155.789376 -13.790168)
		(width 0.127)
		(layer "In4.Cu")
		(net "I3C_SPD_DDRABCD_CPU1_BMC_SDA")
	)
	(segment
		(start 78.228698 -134.486904)
		(end 78.228698 -146.725132)
		(width 0.127)
		(layer "In4.Cu")
		(net "I3C_SPD_DDRABCD_CPU1_BMC_SDA")
	)
	(segment
		(start 163.52012 -9.751568)
		(end 159.60852 -13.663168)
		(width 0.127)
		(layer "In4.Cu")
		(net "I3C_SPD_DDRABCD_CPU1_BMC_SDA")
	)
	(segment
		(start 155.027376 -13.663168)
		(end 154.177492 -13.663168)
		(width 0.127)
		(layer "In4.Cu")
		(net "I3C_SPD_DDRABCD_CPU1_BMC_SDA")
	)
	(segment
		(start 116.515134 -35.005264)
		(end 106.652314 -35.005264)
		(width 0.127)
		(layer "In4.Cu")
		(net "I3C_SPD_DDRABCD_CPU1_BMC_SDA")
	)
	(segment
		(start 159.60852 -13.663168)
		(end 155.916376 -13.663168)
		(width 0.127)
		(layer "In4.Cu")
		(net "I3C_SPD_DDRABCD_CPU1_BMC_SDA")
	)
	(segment
		(start 58.59653 -59.878468)
		(end 55.75808 -62.716918)
		(width 0.127)
		(layer "In4.Cu")
		(net "I3C_SPD_DDRABCD_CPU1_BMC_SDA")
	)
	(segment
		(start 73.475088 -129.733294)
		(end 78.228698 -134.486904)
		(width 0.127)
		(layer "In4.Cu")
		(net "I3C_SPD_DDRABCD_CPU1_BMC_SDA")
	)
	(segment
		(start 181.88178 -12.769088)
		(end 181.348888 -12.769088)
		(width 0.127)
		(layer "In4.Cu")
		(net "I3C_SPD_DDRABCD_CPU1_BMC_SDA")
	)
	(segment
		(start 92.18422 -42.18686)
		(end 89.396062 -43.341798)
		(width 0.127)
		(layer "In4.Cu")
		(net "I3C_SPD_DDRABCD_CPU1_BMC_SDA")
	)
	(segment
		(start 106.652314 -35.005264)
		(end 99.897184 -41.760394)
		(width 0.127)
		(layer "In4.Cu")
		(net "I3C_SPD_DDRABCD_CPU1_BMC_SDA")
	)
	(segment
		(start 183.39816 -14.285468)
		(end 181.88178 -12.769088)
		(width 0.127)
		(layer "In4.Cu")
		(net "I3C_SPD_DDRABCD_CPU1_BMC_SDA")
	)
	(segment
		(start 55.75808 -78.055978)
		(end 73.475088 -95.772986)
		(width 0.127)
		(layer "In4.Cu")
		(net "I3C_SPD_DDRABCD_CPU1_BMC_SDA")
	)
	(segment
		(start 155.789376 -14.262608)
		(end 155.662376 -14.389608)
		(width 0.127)
		(layer "In4.Cu")
		(net "I3C_SPD_DDRABCD_CPU1_BMC_SDA")
	)
	(segment
		(start 141.06398 -23.22068)
		(end 137.108692 -23.22068)
		(width 0.127)
		(layer "In4.Cu")
		(net "I3C_SPD_DDRABCD_CPU1_BMC_SDA")
	)
	(segment
		(start 128.9812 -21.326348)
		(end 125.901704 -24.405844)
		(width 0.127)
		(layer "In4.Cu")
		(net "I3C_SPD_DDRABCD_CPU1_BMC_SDA")
	)
	(segment
		(start 155.154376 -14.262608)
		(end 155.154376 -13.790168)
		(width 0.127)
		(layer "In4.Cu")
		(net "I3C_SPD_DDRABCD_CPU1_BMC_SDA")
	)
	(segment
		(start 155.662376 -14.389608)
		(end 155.281376 -14.389608)
		(width 0.127)
		(layer "In4.Cu")
		(net "I3C_SPD_DDRABCD_CPU1_BMC_SDA")
	)
	(segment
		(start 125.901704 -24.405844)
		(end 125.901704 -25.618694)
		(width 0.127)
		(layer "In4.Cu")
		(net "I3C_SPD_DDRABCD_CPU1_BMC_SDA")
	)
	(segment
		(start 82.01279 -49.568608)
		(end 71.70293 -59.878468)
		(width 0.127)
		(layer "In4.Cu")
		(net "I3C_SPD_DDRABCD_CPU1_BMC_SDA")
	)
	(segment
		(start 146.514312 -21.326348)
		(end 142.958312 -21.326348)
		(width 0.127)
		(layer "In4.Cu")
		(net "I3C_SPD_DDRABCD_CPU1_BMC_SDA")
	)
	(segment
		(start 76.999338 -148.630132)
		(end 78.337918 -148.630132)
		(width 0.12954)
		(layer "F.Cu")
		(net "I3C_SPD_DDRABCD_CPU1_BMC_SCL")
	)
	(via
		(at 186.345068 -14.747748)
		(size 0.508)
		(drill 0.254)
		(layers "F.Cu" "B.Cu")
		(net "I3C_SPD_DDRABCD_CPU1_BMC_SCL")
	)
	(via
		(at 78.337918 -148.630132)
		(size 0.508)
		(drill 0.254)
		(layers "F.Cu" "B.Cu")
		(net "I3C_SPD_DDRABCD_CPU1_BMC_SCL")
	)
	(segment
		(start 186.345068 -14.00048)
		(end 186.345068 -14.747748)
		(width 0.12954)
		(layer "B.Cu")
		(net "I3C_SPD_DDRABCD_CPU1_BMC_SCL")
	)
	(segment
		(start 185.247788 -13.650468)
		(end 186.345068 -14.747748)
		(width 0.127)
		(layer "In4.Cu")
		(net "I3C_SPD_DDRABCD_CPU1_BMC_SCL")
	)
	(segment
		(start 153.877772 -13.028168)
		(end 159.345376 -13.028168)
		(width 0.127)
		(layer "In4.Cu")
		(net "I3C_SPD_DDRABCD_CPU1_BMC_SCL")
	)
	(segment
		(start 140.6525 -22.42566)
		(end 142.386812 -20.691348)
		(width 0.127)
		(layer "In4.Cu")
		(net "I3C_SPD_DDRABCD_CPU1_BMC_SCL")
	)
	(segment
		(start 178.172872 -8.694928)
		(end 181.556152 -12.078208)
		(width 0.127)
		(layer "In4.Cu")
		(net "I3C_SPD_DDRABCD_CPU1_BMC_SCL")
	)
	(segment
		(start 82.381344 -48.882808)
		(end 87.363046 -43.901106)
		(width 0.127)
		(layer "In4.Cu")
		(net "I3C_SPD_DDRABCD_CPU1_BMC_SCL")
	)
	(segment
		(start 125.25248 -25.297892)
		(end 125.25248 -21.952712)
		(width 0.127)
		(layer "In4.Cu")
		(net "I3C_SPD_DDRABCD_CPU1_BMC_SCL")
	)
	(segment
		(start 126.513844 -20.691348)
		(end 135.97382 -20.691348)
		(width 0.127)
		(layer "In4.Cu")
		(net "I3C_SPD_DDRABCD_CPU1_BMC_SCL")
	)
	(segment
		(start 87.363046 -43.901106)
		(end 89.197942 -42.675048)
		(width 0.127)
		(layer "In4.Cu")
		(net "I3C_SPD_DDRABCD_CPU1_BMC_SCL")
	)
	(segment
		(start 181.556152 -12.078208)
		(end 182.089044 -12.078208)
		(width 0.127)
		(layer "In4.Cu")
		(net "I3C_SPD_DDRABCD_CPU1_BMC_SCL")
	)
	(segment
		(start 77.168756 -147.46097)
		(end 77.168756 -135.082788)
		(width 0.127)
		(layer "In4.Cu")
		(net "I3C_SPD_DDRABCD_CPU1_BMC_SCL")
	)
	(segment
		(start 77.168756 -135.082788)
		(end 72.789288 -130.70332)
		(width 0.127)
		(layer "In4.Cu")
		(net "I3C_SPD_DDRABCD_CPU1_BMC_SCL")
	)
	(segment
		(start 72.789288 -96.057212)
		(end 55.07228 -78.340204)
		(width 0.127)
		(layer "In4.Cu")
		(net "I3C_SPD_DDRABCD_CPU1_BMC_SCL")
	)
	(segment
		(start 159.345376 -13.028168)
		(end 163.307776 -9.065768)
		(width 0.127)
		(layer "In4.Cu")
		(net "I3C_SPD_DDRABCD_CPU1_BMC_SCL")
	)
	(segment
		(start 58.312304 -59.192668)
		(end 71.418704 -59.192668)
		(width 0.127)
		(layer "In4.Cu")
		(net "I3C_SPD_DDRABCD_CPU1_BMC_SCL")
	)
	(segment
		(start 91.971114 -41.52646)
		(end 98.773488 -41.52646)
		(width 0.127)
		(layer "In4.Cu")
		(net "I3C_SPD_DDRABCD_CPU1_BMC_SCL")
	)
	(segment
		(start 55.07228 -62.432692)
		(end 58.312304 -59.192668)
		(width 0.127)
		(layer "In4.Cu")
		(net "I3C_SPD_DDRABCD_CPU1_BMC_SCL")
	)
	(segment
		(start 98.773488 -41.52646)
		(end 99.435158 -41.252394)
		(width 0.127)
		(layer "In4.Cu")
		(net "I3C_SPD_DDRABCD_CPU1_BMC_SCL")
	)
	(segment
		(start 81.728564 -48.882808)
		(end 82.381344 -48.882808)
		(width 0.127)
		(layer "In4.Cu")
		(net "I3C_SPD_DDRABCD_CPU1_BMC_SCL")
	)
	(segment
		(start 55.07228 -78.340204)
		(end 55.07228 -62.432692)
		(width 0.127)
		(layer "In4.Cu")
		(net "I3C_SPD_DDRABCD_CPU1_BMC_SCL")
	)
	(segment
		(start 116.230908 -34.319464)
		(end 125.25248 -25.297892)
		(width 0.127)
		(layer "In4.Cu")
		(net "I3C_SPD_DDRABCD_CPU1_BMC_SCL")
	)
	(segment
		(start 71.418704 -59.192668)
		(end 81.728564 -48.882808)
		(width 0.127)
		(layer "In4.Cu")
		(net "I3C_SPD_DDRABCD_CPU1_BMC_SCL")
	)
	(segment
		(start 167.2844 -9.065768)
		(end 167.65524 -8.694928)
		(width 0.127)
		(layer "In4.Cu")
		(net "I3C_SPD_DDRABCD_CPU1_BMC_SCL")
	)
	(segment
		(start 163.307776 -9.065768)
		(end 167.2844 -9.065768)
		(width 0.127)
		(layer "In4.Cu")
		(net "I3C_SPD_DDRABCD_CPU1_BMC_SCL")
	)
	(segment
		(start 167.65524 -8.694928)
		(end 178.172872 -8.694928)
		(width 0.127)
		(layer "In4.Cu")
		(net "I3C_SPD_DDRABCD_CPU1_BMC_SCL")
	)
	(segment
		(start 125.25248 -21.952712)
		(end 126.513844 -20.691348)
		(width 0.127)
		(layer "In4.Cu")
		(net "I3C_SPD_DDRABCD_CPU1_BMC_SCL")
	)
	(segment
		(start 183.661304 -13.650468)
		(end 185.247788 -13.650468)
		(width 0.127)
		(layer "In4.Cu")
		(net "I3C_SPD_DDRABCD_CPU1_BMC_SCL")
	)
	(segment
		(start 99.435158 -41.252394)
		(end 106.368088 -34.319464)
		(width 0.127)
		(layer "In4.Cu")
		(net "I3C_SPD_DDRABCD_CPU1_BMC_SCL")
	)
	(segment
		(start 146.214592 -20.691348)
		(end 153.877772 -13.028168)
		(width 0.127)
		(layer "In4.Cu")
		(net "I3C_SPD_DDRABCD_CPU1_BMC_SCL")
	)
	(segment
		(start 78.337918 -148.630132)
		(end 77.168756 -147.46097)
		(width 0.127)
		(layer "In4.Cu")
		(net "I3C_SPD_DDRABCD_CPU1_BMC_SCL")
	)
	(segment
		(start 89.197942 -42.675048)
		(end 91.971114 -41.52646)
		(width 0.127)
		(layer "In4.Cu")
		(net "I3C_SPD_DDRABCD_CPU1_BMC_SCL")
	)
	(segment
		(start 182.089044 -12.078208)
		(end 183.661304 -13.650468)
		(width 0.127)
		(layer "In4.Cu")
		(net "I3C_SPD_DDRABCD_CPU1_BMC_SCL")
	)
	(segment
		(start 142.386812 -20.691348)
		(end 146.214592 -20.691348)
		(width 0.127)
		(layer "In4.Cu")
		(net "I3C_SPD_DDRABCD_CPU1_BMC_SCL")
	)
	(segment
		(start 106.368088 -34.319464)
		(end 116.230908 -34.319464)
		(width 0.127)
		(layer "In4.Cu")
		(net "I3C_SPD_DDRABCD_CPU1_BMC_SCL")
	)
	(segment
		(start 137.708132 -22.42566)
		(end 140.6525 -22.42566)
		(width 0.127)
		(layer "In4.Cu")
		(net "I3C_SPD_DDRABCD_CPU1_BMC_SCL")
	)
	(segment
		(start 72.789288 -130.70332)
		(end 72.789288 -96.057212)
		(width 0.127)
		(layer "In4.Cu")
		(net "I3C_SPD_DDRABCD_CPU1_BMC_SCL")
	)
	(segment
		(start 135.97382 -20.691348)
		(end 137.708132 -22.42566)
		(width 0.127)
		(layer "In4.Cu")
		(net "I3C_SPD_DDRABCD_CPU1_BMC_SCL")
	)
	(segment
		(start 185.662062 -12.683998)
		(end 185.661808 -12.683744)
		(width 0.12954)
		(layer "F.Cu")
		(net "I3C_SPD_DDRABCD_CPU1_BMC_R_SDA")
	)
	(segment
		(start 185.662062 -13.600176)
		(end 185.662062 -12.683998)
		(width 0.12954)
		(layer "F.Cu")
		(net "I3C_SPD_DDRABCD_CPU1_BMC_R_SDA")
	)
	(segment
		(start 185.661808 -11.631676)
		(end 185.09488 -11.064748)
		(width 0.12954)
		(layer "F.Cu")
		(net "I3C_SPD_DDRABCD_CPU1_BMC_R_SDA")
	)
	(segment
		(start 185.661808 -12.683744)
		(end 185.661808 -11.631676)
		(width 0.12954)
		(layer "F.Cu")
		(net "I3C_SPD_DDRABCD_CPU1_BMC_R_SDA")
	)
	(via
		(at 185.09488 -11.064748)
		(size 0.508)
		(drill 0.254)
		(layers "F.Cu" "B.Cu")
		(net "I3C_SPD_DDRABCD_CPU1_BMC_R_SDA")
	)
	(segment
		(start 185.09488 -11.064748)
		(end 185.240422 -11.21029)
		(width 0.12954)
		(layer "B.Cu")
		(net "I3C_SPD_DDRABCD_CPU1_BMC_R_SDA")
	)
	(segment
		(start 185.240422 -11.21029)
		(end 185.240422 -13.20038)
		(width 0.12954)
		(layer "B.Cu")
		(net "I3C_SPD_DDRABCD_CPU1_BMC_R_SDA")
	)
	(segment
		(start 186.261756 -12.683744)
		(end 186.261756 -10.378948)
		(width 0.12954)
		(layer "F.Cu")
		(net "I3C_SPD_DDRABCD_CPU1_BMC_R_SCL")
	)
	(segment
		(start 186.26201 -13.600176)
		(end 186.26201 -12.683998)
		(width 0.12954)
		(layer "F.Cu")
		(net "I3C_SPD_DDRABCD_CPU1_BMC_R_SCL")
	)
	(segment
		(start 186.26201 -12.683998)
		(end 186.261756 -12.683744)
		(width 0.12954)
		(layer "F.Cu")
		(net "I3C_SPD_DDRABCD_CPU1_BMC_R_SCL")
	)
	(via
		(at 186.261756 -10.378948)
		(size 0.508)
		(drill 0.254)
		(layers "F.Cu" "B.Cu")
		(net "I3C_SPD_DDRABCD_CPU1_BMC_R_SCL")
	)
	(segment
		(start 186.261756 -10.812272)
		(end 186.345068 -10.895584)
		(width 0.12954)
		(layer "B.Cu")
		(net "I3C_SPD_DDRABCD_CPU1_BMC_R_SCL")
	)
	(segment
		(start 186.345068 -10.895584)
		(end 186.345068 -13.20038)
		(width 0.12954)
		(layer "B.Cu")
		(net "I3C_SPD_DDRABCD_CPU1_BMC_R_SCL")
	)
	(segment
		(start 186.261756 -10.378948)
		(end 186.261756 -10.812272)
		(width 0.12954)
		(layer "B.Cu")
		(net "I3C_SPD_DDRABCD_CPU1_BMC_R_SCL")
	)
	(segment
		(start 360.51998 -230.900732)
		(end 360.520234 -230.900478)
		(width 0.12954)
		(layer "F.Cu")
		(net "I3C_SPD_DDRABCD_CPU0_SDA")
	)
	(segment
		(start 360.51998 -231.436418)
		(end 360.51998 -230.900732)
		(width 0.12954)
		(layer "F.Cu")
		(net "I3C_SPD_DDRABCD_CPU0_SDA")
	)
	(via
		(at 338.568538 -194.83959)
		(size 0.6604)
		(drill 0.3302)
		(layers "F.Cu" "B.Cu")
		(net "I3C_SPD_DDRABCD_CPU0_SDA")
	)
	(via
		(at 360.520234 -230.900478)
		(size 0.4572)
		(drill 0.2032)
		(layers "F.Cu" "B.Cu")
		(net "I3C_SPD_DDRABCD_CPU0_SDA")
	)
	(segment
		(start 355.547168 -221.628462)
		(end 355.538278 -221.623382)
		(width 0.0889)
		(layer "B.Cu")
		(net "I3C_SPD_DDRABCD_CPU0_SDA")
	)
	(segment
		(start 356.017322 -222.442278)
		(end 356.008432 -222.437198)
		(width 0.0889)
		(layer "B.Cu")
		(net "I3C_SPD_DDRABCD_CPU0_SDA")
	)
	(segment
		(start 358.827832 -228.948488)
		(end 358.81564 -228.941376)
		(width 0.0889)
		(layer "B.Cu")
		(net "I3C_SPD_DDRABCD_CPU0_SDA")
	)
	(segment
		(start 337.212432 -219.18168)
		(end 337.206336 -219.178124)
		(width 0.0889)
		(layer "B.Cu")
		(net "I3C_SPD_DDRABCD_CPU0_SDA")
	)
	(segment
		(start 357.135684 -226.032822)
		(end 357.135684 -226.017328)
		(width 0.0889)
		(layer "B.Cu")
		(net "I3C_SPD_DDRABCD_CPU0_SDA")
	)
	(segment
		(start 357.426768 -226.511866)
		(end 357.417878 -226.506786)
		(width 0.0889)
		(layer "B.Cu")
		(net "I3C_SPD_DDRABCD_CPU0_SDA")
	)
	(segment
		(start 338.564474 -191.132968)
		(end 338.975446 -191.132968)
		(width 0.12954)
		(layer "B.Cu")
		(net "I3C_SPD_DDRABCD_CPU0_SDA")
	)
	(segment
		(start 335.802478 -216.739978)
		(end 335.790286 -216.732866)
		(width 0.0889)
		(layer "B.Cu")
		(net "I3C_SPD_DDRABCD_CPU0_SDA")
	)
	(segment
		(start 356.005638 -222.435674)
		(end 356.002336 -222.433642)
		(width 0.0889)
		(layer "B.Cu")
		(net "I3C_SPD_DDRABCD_CPU0_SDA")
	)
	(segment
		(start 333.651098 -212.720428)
		(end 333.651098 -204.42809)
		(width 0.12954)
		(layer "B.Cu")
		(net "I3C_SPD_DDRABCD_CPU0_SDA")
	)
	(segment
		(start 360.520234 -230.900478)
		(end 360.520234 -230.547926)
		(width 0.0889)
		(layer "B.Cu")
		(net "I3C_SPD_DDRABCD_CPU0_SDA")
	)
	(segment
		(start 345.685364 -219.190316)
		(end 345.670632 -219.18168)
		(width 0.0889)
		(layer "B.Cu")
		(net "I3C_SPD_DDRABCD_CPU0_SDA")
	)
	(segment
		(start 353.284282 -219.995496)
		(end 353.273868 -220.001592)
		(width 0.0889)
		(layer "B.Cu")
		(net "I3C_SPD_DDRABCD_CPU0_SDA")
	)
	(segment
		(start 340.986364 -219.190316)
		(end 340.971632 -219.18168)
		(width 0.0889)
		(layer "B.Cu")
		(net "I3C_SPD_DDRABCD_CPU0_SDA")
	)
	(segment
		(start 360.461052 -230.488744)
		(end 360.461052 -230.28529)
		(width 0.0889)
		(layer "B.Cu")
		(net "I3C_SPD_DDRABCD_CPU0_SDA")
	)
	(segment
		(start 359.297732 -229.762304)
		(end 359.291636 -229.758748)
		(width 0.0889)
		(layer "B.Cu")
		(net "I3C_SPD_DDRABCD_CPU0_SDA")
	)
	(segment
		(start 335.05013 -215.452198)
		(end 334.83423 -215.236298)
		(width 0.0889)
		(layer "B.Cu")
		(net "I3C_SPD_DDRABCD_CPU0_SDA")
	)
	(segment
		(start 354.78593 -220.334078)
		(end 354.78593 -220.311218)
		(width 0.0889)
		(layer "B.Cu")
		(net "I3C_SPD_DDRABCD_CPU0_SDA")
	)
	(segment
		(start 334.83423 -214.88527)
		(end 334.83423 -213.90356)
		(width 0.12954)
		(layer "B.Cu")
		(net "I3C_SPD_DDRABCD_CPU0_SDA")
	)
	(segment
		(start 336.92973 -218.692222)
		(end 336.92973 -218.683586)
		(width 0.0889)
		(layer "B.Cu")
		(net "I3C_SPD_DDRABCD_CPU0_SDA")
	)
	(segment
		(start 343.805764 -219.190316)
		(end 343.791032 -219.18168)
		(width 0.0889)
		(layer "B.Cu")
		(net "I3C_SPD_DDRABCD_CPU0_SDA")
	)
	(segment
		(start 356.957122 -225.69805)
		(end 356.948232 -225.69297)
		(width 0.0889)
		(layer "B.Cu")
		(net "I3C_SPD_DDRABCD_CPU0_SDA")
	)
	(segment
		(start 356.66553 -223.584262)
		(end 356.66553 -223.56699)
		(width 0.0889)
		(layer "B.Cu")
		(net "I3C_SPD_DDRABCD_CPU0_SDA")
	)
	(segment
		(start 346.625164 -219.190316)
		(end 346.610432 -219.18168)
		(width 0.0889)
		(layer "B.Cu")
		(net "I3C_SPD_DDRABCD_CPU0_SDA")
	)
	(segment
		(start 338.568538 -194.83959)
		(end 338.045552 -194.316604)
		(width 0.12954)
		(layer "B.Cu")
		(net "I3C_SPD_DDRABCD_CPU0_SDA")
	)
	(segment
		(start 338.568538 -199.51065)
		(end 338.568538 -194.83959)
		(width 0.12954)
		(layer "B.Cu")
		(net "I3C_SPD_DDRABCD_CPU0_SDA")
	)
	(segment
		(start 348.504764 -219.190316)
		(end 348.490032 -219.18168)
		(width 0.0889)
		(layer "B.Cu")
		(net "I3C_SPD_DDRABCD_CPU0_SDA")
	)
	(segment
		(start 335.341214 -215.931242)
		(end 335.332324 -215.926162)
		(width 0.0889)
		(layer "B.Cu")
		(net "I3C_SPD_DDRABCD_CPU0_SDA")
	)
	(segment
		(start 349.444564 -219.190316)
		(end 349.429832 -219.18168)
		(width 0.0889)
		(layer "B.Cu")
		(net "I3C_SPD_DDRABCD_CPU0_SDA")
	)
	(segment
		(start 356.008432 -222.437198)
		(end 356.005638 -222.435674)
		(width 0.0889)
		(layer "B.Cu")
		(net "I3C_SPD_DDRABCD_CPU0_SDA")
	)
	(segment
		(start 339.106764 -219.190316)
		(end 339.092032 -219.18168)
		(width 0.0889)
		(layer "B.Cu")
		(net "I3C_SPD_DDRABCD_CPU0_SDA")
	)
	(segment
		(start 356.66553 -225.217482)
		(end 356.66553 -225.203258)
		(width 0.0889)
		(layer "B.Cu")
		(net "I3C_SPD_DDRABCD_CPU0_SDA")
	)
	(segment
		(start 355.256084 -221.149418)
		(end 355.256084 -221.133924)
		(width 0.0889)
		(layer "B.Cu")
		(net "I3C_SPD_DDRABCD_CPU0_SDA")
	)
	(segment
		(start 352.436684 -219.515944)
		(end 352.436684 -219.506038)
		(width 0.0889)
		(layer "B.Cu")
		(net "I3C_SPD_DDRABCD_CPU0_SDA")
	)
	(segment
		(start 355.077522 -220.814646)
		(end 355.068632 -220.809566)
		(width 0.0889)
		(layer "B.Cu")
		(net "I3C_SPD_DDRABCD_CPU0_SDA")
	)
	(segment
		(start 336.460084 -217.888312)
		(end 336.460084 -217.878406)
		(width 0.0889)
		(layer "B.Cu")
		(net "I3C_SPD_DDRABCD_CPU0_SDA")
	)
	(segment
		(start 333.651098 -204.42809)
		(end 338.568538 -199.51065)
		(width 0.12954)
		(layer "B.Cu")
		(net "I3C_SPD_DDRABCD_CPU0_SDA")
	)
	(segment
		(start 356.195884 -224.404936)
		(end 356.195884 -224.379536)
		(width 0.0889)
		(layer "B.Cu")
		(net "I3C_SPD_DDRABCD_CPU0_SDA")
	)
	(segment
		(start 356.486968 -224.88398)
		(end 356.478078 -224.8789)
		(width 0.0889)
		(layer "B.Cu")
		(net "I3C_SPD_DDRABCD_CPU0_SDA")
	)
	(segment
		(start 347.564964 -219.190316)
		(end 347.550232 -219.18168)
		(width 0.0889)
		(layer "B.Cu")
		(net "I3C_SPD_DDRABCD_CPU0_SDA")
	)
	(segment
		(start 356.195884 -222.780098)
		(end 356.195884 -222.761556)
		(width 0.0889)
		(layer "B.Cu")
		(net "I3C_SPD_DDRABCD_CPU0_SDA")
	)
	(segment
		(start 338.068666 -191.133222)
		(end 338.56422 -191.133222)
		(width 0.12954)
		(layer "B.Cu")
		(net "I3C_SPD_DDRABCD_CPU0_SDA")
	)
	(segment
		(start 360.425238 -230.102156)
		(end 360.425238 -230.086662)
		(width 0.0889)
		(layer "B.Cu")
		(net "I3C_SPD_DDRABCD_CPU0_SDA")
	)
	(segment
		(start 360.425238 -230.086662)
		(end 360.424984 -230.086662)
		(width 0.0889)
		(layer "B.Cu")
		(net "I3C_SPD_DDRABCD_CPU0_SDA")
	)
	(segment
		(start 338.166964 -219.190316)
		(end 338.152232 -219.18168)
		(width 0.0889)
		(layer "B.Cu")
		(net "I3C_SPD_DDRABCD_CPU0_SDA")
	)
	(segment
		(start 360.246422 -229.767384)
		(end 360.237532 -229.762304)
		(width 0.0889)
		(layer "B.Cu")
		(net "I3C_SPD_DDRABCD_CPU0_SDA")
	)
	(segment
		(start 336.281522 -217.559128)
		(end 336.272632 -217.554048)
		(width 0.0889)
		(layer "B.Cu")
		(net "I3C_SPD_DDRABCD_CPU0_SDA")
	)
	(segment
		(start 359.312464 -229.77094)
		(end 359.297732 -229.762304)
		(width 0.0889)
		(layer "B.Cu")
		(net "I3C_SPD_DDRABCD_CPU0_SDA")
	)
	(segment
		(start 340.046564 -219.190316)
		(end 340.031832 -219.18168)
		(width 0.0889)
		(layer "B.Cu")
		(net "I3C_SPD_DDRABCD_CPU0_SDA")
	)
	(segment
		(start 334.83423 -213.90356)
		(end 333.651098 -212.720428)
		(width 0.12954)
		(layer "B.Cu")
		(net "I3C_SPD_DDRABCD_CPU0_SDA")
	)
	(segment
		(start 338.045552 -194.316604)
		(end 338.045552 -191.156336)
		(width 0.12954)
		(layer "B.Cu")
		(net "I3C_SPD_DDRABCD_CPU0_SDA")
	)
	(segment
		(start 358.075484 -227.667058)
		(end 358.075484 -227.64496)
		(width 0.0889)
		(layer "B.Cu")
		(net "I3C_SPD_DDRABCD_CPU0_SDA")
	)
	(segment
		(start 358.366568 -228.139752)
		(end 358.357678 -228.134672)
		(width 0.0889)
		(layer "B.Cu")
		(net "I3C_SPD_DDRABCD_CPU0_SDA")
	)
	(segment
		(start 338.045552 -191.156336)
		(end 338.068666 -191.133222)
		(width 0.12954)
		(layer "B.Cu")
		(net "I3C_SPD_DDRABCD_CPU0_SDA")
	)
	(segment
		(start 335.98993 -217.07856)
		(end 335.98993 -217.064336)
		(width 0.0889)
		(layer "B.Cu")
		(net "I3C_SPD_DDRABCD_CPU0_SDA")
	)
	(segment
		(start 352.258122 -219.18676)
		(end 352.249232 -219.18168)
		(width 0.0889)
		(layer "B.Cu")
		(net "I3C_SPD_DDRABCD_CPU0_SDA")
	)
	(segment
		(start 338.56422 -191.133222)
		(end 338.564474 -191.132968)
		(width 0.12954)
		(layer "B.Cu")
		(net "I3C_SPD_DDRABCD_CPU0_SDA")
	)
	(segment
		(start 338.975446 -191.132968)
		(end 338.998814 -191.156336)
		(width 0.12954)
		(layer "B.Cu")
		(net "I3C_SPD_DDRABCD_CPU0_SDA")
	)
	(segment
		(start 334.83423 -215.236298)
		(end 334.83423 -214.88527)
		(width 0.0889)
		(layer "B.Cu")
		(net "I3C_SPD_DDRABCD_CPU0_SDA")
	)
	(segment
		(start 357.888032 -227.320602)
		(end 357.87584 -227.31349)
		(width 0.0889)
		(layer "B.Cu")
		(net "I3C_SPD_DDRABCD_CPU0_SDA")
	)
	(segment
		(start 359.01503 -229.272846)
		(end 359.01503 -229.26421)
		(width 0.0889)
		(layer "B.Cu")
		(net "I3C_SPD_DDRABCD_CPU0_SDA")
	)
	(segment
		(start 357.896922 -227.325682)
		(end 357.888032 -227.320602)
		(width 0.0889)
		(layer "B.Cu")
		(net "I3C_SPD_DDRABCD_CPU0_SDA")
	)
	(segment
		(start 350.384364 -219.190316)
		(end 350.369632 -219.18168)
		(width 0.0889)
		(layer "B.Cu")
		(net "I3C_SPD_DDRABCD_CPU0_SDA")
	)
	(segment
		(start 351.324164 -219.190316)
		(end 351.309432 -219.18168)
		(width 0.0889)
		(layer "B.Cu")
		(net "I3C_SPD_DDRABCD_CPU0_SDA")
	)
	(segment
		(start 337.227164 -219.190316)
		(end 337.212432 -219.18168)
		(width 0.0889)
		(layer "B.Cu")
		(net "I3C_SPD_DDRABCD_CPU0_SDA")
	)
	(segment
		(start 344.745564 -219.190316)
		(end 344.730832 -219.18168)
		(width 0.0889)
		(layer "B.Cu")
		(net "I3C_SPD_DDRABCD_CPU0_SDA")
	)
	(segment
		(start 360.520234 -230.547926)
		(end 360.461052 -230.488744)
		(width 0.0889)
		(layer "B.Cu")
		(net "I3C_SPD_DDRABCD_CPU0_SDA")
	)
	(segment
		(start 341.926164 -219.190316)
		(end 341.911432 -219.18168)
		(width 0.0889)
		(layer "B.Cu")
		(net "I3C_SPD_DDRABCD_CPU0_SDA")
	)
	(segment
		(start 354.224336 -219.995496)
		(end 354.213922 -220.001592)
		(width 0.0889)
		(layer "B.Cu")
		(net "I3C_SPD_DDRABCD_CPU0_SDA")
	)
	(segment
		(start 335.811368 -216.745058)
		(end 335.802478 -216.739978)
		(width 0.0889)
		(layer "B.Cu")
		(net "I3C_SPD_DDRABCD_CPU0_SDA")
	)
	(segment
		(start 342.865964 -219.190316)
		(end 342.851232 -219.18168)
		(width 0.0889)
		(layer "B.Cu")
		(net "I3C_SPD_DDRABCD_CPU0_SDA")
	)
	(arc
		(start 359.863136 -229.762304)
		(mid 359.588937 -229.838139)
		(end 359.312464 -229.77094)
		(width 0.0889)
		(layer "B.Cu")
		(net "I3C_SPD_DDRABCD_CPU0_SDA")
	)
	(arc
		(start 347.175836 -219.18168)
		(mid 346.901637 -219.257515)
		(end 346.625164 -219.190316)
		(width 0.0889)
		(layer "B.Cu")
		(net "I3C_SPD_DDRABCD_CPU0_SDA")
	)
	(arc
		(start 345.296236 -219.18168)
		(mid 345.022037 -219.257515)
		(end 344.745564 -219.190316)
		(width 0.0889)
		(layer "B.Cu")
		(net "I3C_SPD_DDRABCD_CPU0_SDA")
	)
	(arc
		(start 355.256084 -221.133924)
		(mid 355.208405 -220.951024)
		(end 355.077522 -220.814646)
		(width 0.0889)
		(layer "B.Cu")
		(net "I3C_SPD_DDRABCD_CPU0_SDA")
	)
	(arc
		(start 346.236036 -219.18168)
		(mid 345.961837 -219.257515)
		(end 345.685364 -219.190316)
		(width 0.0889)
		(layer "B.Cu")
		(net "I3C_SPD_DDRABCD_CPU0_SDA")
	)
	(arc
		(start 356.478332 -223.251268)
		(mid 356.276046 -223.052287)
		(end 356.195884 -222.780098)
		(width 0.0889)
		(layer "B.Cu")
		(net "I3C_SPD_DDRABCD_CPU0_SDA")
	)
	(arc
		(start 348.115636 -219.18168)
		(mid 347.841437 -219.257515)
		(end 347.564964 -219.190316)
		(width 0.0889)
		(layer "B.Cu")
		(net "I3C_SPD_DDRABCD_CPU0_SDA")
	)
	(arc
		(start 344.730832 -219.18168)
		(mid 344.543634 -219.131537)
		(end 344.356436 -219.18168)
		(width 0.0889)
		(layer "B.Cu")
		(net "I3C_SPD_DDRABCD_CPU0_SDA")
	)
	(arc
		(start 338.717636 -219.18168)
		(mid 338.443437 -219.257515)
		(end 338.166964 -219.190316)
		(width 0.0889)
		(layer "B.Cu")
		(net "I3C_SPD_DDRABCD_CPU0_SDA")
	)
	(arc
		(start 336.742532 -218.367864)
		(mid 336.538197 -218.165259)
		(end 336.460084 -217.888312)
		(width 0.0889)
		(layer "B.Cu")
		(net "I3C_SPD_DDRABCD_CPU0_SDA")
	)
	(arc
		(start 358.357678 -228.134672)
		(mid 358.156396 -227.937185)
		(end 358.075484 -227.667058)
		(width 0.0889)
		(layer "B.Cu")
		(net "I3C_SPD_DDRABCD_CPU0_SDA")
	)
	(arc
		(start 344.356436 -219.18168)
		(mid 344.082237 -219.257515)
		(end 343.805764 -219.190316)
		(width 0.0889)
		(layer "B.Cu")
		(net "I3C_SPD_DDRABCD_CPU0_SDA")
	)
	(arc
		(start 337.777836 -219.18168)
		(mid 337.503637 -219.257515)
		(end 337.227164 -219.190316)
		(width 0.0889)
		(layer "B.Cu")
		(net "I3C_SPD_DDRABCD_CPU0_SDA")
	)
	(arc
		(start 335.519776 -216.25052)
		(mid 335.472097 -216.06762)
		(end 335.341214 -215.931242)
		(width 0.0889)
		(layer "B.Cu")
		(net "I3C_SPD_DDRABCD_CPU0_SDA")
	)
	(arc
		(start 340.971632 -219.18168)
		(mid 340.784434 -219.131537)
		(end 340.597236 -219.18168)
		(width 0.0889)
		(layer "B.Cu")
		(net "I3C_SPD_DDRABCD_CPU0_SDA")
	)
	(arc
		(start 358.81564 -228.941376)
		(mid 358.617412 -228.735528)
		(end 358.54513 -228.45903)
		(width 0.0889)
		(layer "B.Cu")
		(net "I3C_SPD_DDRABCD_CPU0_SDA")
	)
	(arc
		(start 355.72573 -221.94774)
		(mid 355.678051 -221.76484)
		(end 355.547168 -221.628462)
		(width 0.0889)
		(layer "B.Cu")
		(net "I3C_SPD_DDRABCD_CPU0_SDA")
	)
	(arc
		(start 359.01503 -229.26421)
		(mid 358.96276 -229.081845)
		(end 358.827832 -228.948488)
		(width 0.0889)
		(layer "B.Cu")
		(net "I3C_SPD_DDRABCD_CPU0_SDA")
	)
	(arc
		(start 360.237532 -229.762304)
		(mid 360.050334 -229.712161)
		(end 359.863136 -229.762304)
		(width 0.0889)
		(layer "B.Cu")
		(net "I3C_SPD_DDRABCD_CPU0_SDA")
	)
	(arc
		(start 336.92973 -218.683586)
		(mid 336.87746 -218.501221)
		(end 336.742532 -218.367864)
		(width 0.0889)
		(layer "B.Cu")
		(net "I3C_SPD_DDRABCD_CPU0_SDA")
	)
	(arc
		(start 358.075484 -227.64496)
		(mid 358.027805 -227.46206)
		(end 357.896922 -227.325682)
		(width 0.0889)
		(layer "B.Cu")
		(net "I3C_SPD_DDRABCD_CPU0_SDA")
	)
	(arc
		(start 358.54513 -228.45903)
		(mid 358.497451 -228.27613)
		(end 358.366568 -228.139752)
		(width 0.0889)
		(layer "B.Cu")
		(net "I3C_SPD_DDRABCD_CPU0_SDA")
	)
	(arc
		(start 352.436684 -219.506038)
		(mid 352.389005 -219.323138)
		(end 352.258122 -219.18676)
		(width 0.0889)
		(layer "B.Cu")
		(net "I3C_SPD_DDRABCD_CPU0_SDA")
	)
	(arc
		(start 352.249232 -219.18168)
		(mid 352.062034 -219.131537)
		(end 351.874836 -219.18168)
		(width 0.0889)
		(layer "B.Cu")
		(net "I3C_SPD_DDRABCD_CPU0_SDA")
	)
	(arc
		(start 354.598732 -219.995496)
		(mid 354.411534 -219.945353)
		(end 354.224336 -219.995496)
		(width 0.0889)
		(layer "B.Cu")
		(net "I3C_SPD_DDRABCD_CPU0_SDA")
	)
	(arc
		(start 348.490032 -219.18168)
		(mid 348.302834 -219.131537)
		(end 348.115636 -219.18168)
		(width 0.0889)
		(layer "B.Cu")
		(net "I3C_SPD_DDRABCD_CPU0_SDA")
	)
	(arc
		(start 347.550232 -219.18168)
		(mid 347.363034 -219.131537)
		(end 347.175836 -219.18168)
		(width 0.0889)
		(layer "B.Cu")
		(net "I3C_SPD_DDRABCD_CPU0_SDA")
	)
	(arc
		(start 350.369632 -219.18168)
		(mid 350.182434 -219.131537)
		(end 349.995236 -219.18168)
		(width 0.0889)
		(layer "B.Cu")
		(net "I3C_SPD_DDRABCD_CPU0_SDA")
	)
	(arc
		(start 338.152232 -219.18168)
		(mid 337.965034 -219.131537)
		(end 337.777836 -219.18168)
		(width 0.0889)
		(layer "B.Cu")
		(net "I3C_SPD_DDRABCD_CPU0_SDA")
	)
	(arc
		(start 356.195884 -222.761556)
		(mid 356.148205 -222.578656)
		(end 356.017322 -222.442278)
		(width 0.0889)
		(layer "B.Cu")
		(net "I3C_SPD_DDRABCD_CPU0_SDA")
	)
	(arc
		(start 349.995236 -219.18168)
		(mid 349.721037 -219.257515)
		(end 349.444564 -219.190316)
		(width 0.0889)
		(layer "B.Cu")
		(net "I3C_SPD_DDRABCD_CPU0_SDA")
	)
	(arc
		(start 339.657436 -219.18168)
		(mid 339.383237 -219.257515)
		(end 339.106764 -219.190316)
		(width 0.0889)
		(layer "B.Cu")
		(net "I3C_SPD_DDRABCD_CPU0_SDA")
	)
	(arc
		(start 355.538278 -221.623382)
		(mid 355.335455 -221.423151)
		(end 355.256084 -221.149418)
		(width 0.0889)
		(layer "B.Cu")
		(net "I3C_SPD_DDRABCD_CPU0_SDA")
	)
	(arc
		(start 339.092032 -219.18168)
		(mid 338.904834 -219.131537)
		(end 338.717636 -219.18168)
		(width 0.0889)
		(layer "B.Cu")
		(net "I3C_SPD_DDRABCD_CPU0_SDA")
	)
	(arc
		(start 337.206336 -219.178124)
		(mid 337.003749 -218.971773)
		(end 336.92973 -218.692222)
		(width 0.0889)
		(layer "B.Cu")
		(net "I3C_SPD_DDRABCD_CPU0_SDA")
	)
	(arc
		(start 355.068632 -220.809566)
		(mid 354.865151 -220.608762)
		(end 354.78593 -220.334078)
		(width 0.0889)
		(layer "B.Cu")
		(net "I3C_SPD_DDRABCD_CPU0_SDA")
	)
	(arc
		(start 340.031832 -219.18168)
		(mid 339.844634 -219.131537)
		(end 339.657436 -219.18168)
		(width 0.0889)
		(layer "B.Cu")
		(net "I3C_SPD_DDRABCD_CPU0_SDA")
	)
	(arc
		(start 335.332324 -215.926162)
		(mid 335.129501 -215.725931)
		(end 335.05013 -215.452198)
		(width 0.0889)
		(layer "B.Cu")
		(net "I3C_SPD_DDRABCD_CPU0_SDA")
	)
	(arc
		(start 352.719132 -219.995496)
		(mid 352.514797 -219.792891)
		(end 352.436684 -219.515944)
		(width 0.0889)
		(layer "B.Cu")
		(net "I3C_SPD_DDRABCD_CPU0_SDA")
	)
	(arc
		(start 343.416636 -219.18168)
		(mid 343.142437 -219.257515)
		(end 342.865964 -219.190316)
		(width 0.0889)
		(layer "B.Cu")
		(net "I3C_SPD_DDRABCD_CPU0_SDA")
	)
	(arc
		(start 357.87584 -227.31349)
		(mid 357.677612 -227.107642)
		(end 357.60533 -226.831144)
		(width 0.0889)
		(layer "B.Cu")
		(net "I3C_SPD_DDRABCD_CPU0_SDA")
	)
	(arc
		(start 342.851232 -219.18168)
		(mid 342.664034 -219.131537)
		(end 342.476836 -219.18168)
		(width 0.0889)
		(layer "B.Cu")
		(net "I3C_SPD_DDRABCD_CPU0_SDA")
	)
	(arc
		(start 360.424984 -230.086662)
		(mid 360.377305 -229.903762)
		(end 360.246422 -229.767384)
		(width 0.0889)
		(layer "B.Cu")
		(net "I3C_SPD_DDRABCD_CPU0_SDA")
	)
	(arc
		(start 359.291636 -229.758748)
		(mid 359.089049 -229.552397)
		(end 359.01503 -229.272846)
		(width 0.0889)
		(layer "B.Cu")
		(net "I3C_SPD_DDRABCD_CPU0_SDA")
	)
	(arc
		(start 340.597236 -219.18168)
		(mid 340.323037 -219.257515)
		(end 340.046564 -219.190316)
		(width 0.0889)
		(layer "B.Cu")
		(net "I3C_SPD_DDRABCD_CPU0_SDA")
	)
	(arc
		(start 336.272632 -217.554048)
		(mid 336.069151 -217.353244)
		(end 335.98993 -217.07856)
		(width 0.0889)
		(layer "B.Cu")
		(net "I3C_SPD_DDRABCD_CPU0_SDA")
	)
	(arc
		(start 346.610432 -219.18168)
		(mid 346.423234 -219.131537)
		(end 346.236036 -219.18168)
		(width 0.0889)
		(layer "B.Cu")
		(net "I3C_SPD_DDRABCD_CPU0_SDA")
	)
	(arc
		(start 341.911432 -219.18168)
		(mid 341.724234 -219.131537)
		(end 341.537036 -219.18168)
		(width 0.0889)
		(layer "B.Cu")
		(net "I3C_SPD_DDRABCD_CPU0_SDA")
	)
	(arc
		(start 351.874836 -219.18168)
		(mid 351.600637 -219.257515)
		(end 351.324164 -219.190316)
		(width 0.0889)
		(layer "B.Cu")
		(net "I3C_SPD_DDRABCD_CPU0_SDA")
	)
	(arc
		(start 354.213922 -220.001592)
		(mid 353.93549 -220.071438)
		(end 353.658678 -219.995496)
		(width 0.0889)
		(layer "B.Cu")
		(net "I3C_SPD_DDRABCD_CPU0_SDA")
	)
	(arc
		(start 343.791032 -219.18168)
		(mid 343.603834 -219.131537)
		(end 343.416636 -219.18168)
		(width 0.0889)
		(layer "B.Cu")
		(net "I3C_SPD_DDRABCD_CPU0_SDA")
	)
	(arc
		(start 357.135684 -226.017328)
		(mid 357.088005 -225.834428)
		(end 356.957122 -225.69805)
		(width 0.0889)
		(layer "B.Cu")
		(net "I3C_SPD_DDRABCD_CPU0_SDA")
	)
	(arc
		(start 360.461052 -230.28529)
		(mid 360.435531 -230.195212)
		(end 360.425238 -230.102156)
		(width 0.0889)
		(layer "B.Cu")
		(net "I3C_SPD_DDRABCD_CPU0_SDA")
	)
	(arc
		(start 342.476836 -219.18168)
		(mid 342.202637 -219.257515)
		(end 341.926164 -219.190316)
		(width 0.0889)
		(layer "B.Cu")
		(net "I3C_SPD_DDRABCD_CPU0_SDA")
	)
	(arc
		(start 336.460084 -217.878406)
		(mid 336.412405 -217.695506)
		(end 336.281522 -217.559128)
		(width 0.0889)
		(layer "B.Cu")
		(net "I3C_SPD_DDRABCD_CPU0_SDA")
	)
	(arc
		(start 356.002336 -222.433642)
		(mid 355.799749 -222.227291)
		(end 355.72573 -221.94774)
		(width 0.0889)
		(layer "B.Cu")
		(net "I3C_SPD_DDRABCD_CPU0_SDA")
	)
	(arc
		(start 353.658678 -219.995496)
		(mid 353.47148 -219.945353)
		(end 353.284282 -219.995496)
		(width 0.0889)
		(layer "B.Cu")
		(net "I3C_SPD_DDRABCD_CPU0_SDA")
	)
	(arc
		(start 357.60533 -226.831144)
		(mid 357.557651 -226.648244)
		(end 357.426768 -226.511866)
		(width 0.0889)
		(layer "B.Cu")
		(net "I3C_SPD_DDRABCD_CPU0_SDA")
	)
	(arc
		(start 350.935036 -219.18168)
		(mid 350.660837 -219.257515)
		(end 350.384364 -219.190316)
		(width 0.0889)
		(layer "B.Cu")
		(net "I3C_SPD_DDRABCD_CPU0_SDA")
	)
	(arc
		(start 353.273868 -220.001592)
		(mid 352.99569 -220.071315)
		(end 352.719132 -219.995496)
		(width 0.0889)
		(layer "B.Cu")
		(net "I3C_SPD_DDRABCD_CPU0_SDA")
	)
	(arc
		(start 356.66553 -223.56699)
		(mid 356.61326 -223.384625)
		(end 356.478332 -223.251268)
		(width 0.0889)
		(layer "B.Cu")
		(net "I3C_SPD_DDRABCD_CPU0_SDA")
	)
	(arc
		(start 357.417878 -226.506786)
		(mid 357.215055 -226.306555)
		(end 357.135684 -226.032822)
		(width 0.0889)
		(layer "B.Cu")
		(net "I3C_SPD_DDRABCD_CPU0_SDA")
	)
	(arc
		(start 356.948232 -225.69297)
		(mid 356.744751 -225.492166)
		(end 356.66553 -225.217482)
		(width 0.0889)
		(layer "B.Cu")
		(net "I3C_SPD_DDRABCD_CPU0_SDA")
	)
	(arc
		(start 356.478078 -224.8789)
		(mid 356.275255 -224.678669)
		(end 356.195884 -224.404936)
		(width 0.0889)
		(layer "B.Cu")
		(net "I3C_SPD_DDRABCD_CPU0_SDA")
	)
	(arc
		(start 354.78593 -220.311218)
		(mid 354.73366 -220.128853)
		(end 354.598732 -219.995496)
		(width 0.0889)
		(layer "B.Cu")
		(net "I3C_SPD_DDRABCD_CPU0_SDA")
	)
	(arc
		(start 351.309432 -219.18168)
		(mid 351.122234 -219.131537)
		(end 350.935036 -219.18168)
		(width 0.0889)
		(layer "B.Cu")
		(net "I3C_SPD_DDRABCD_CPU0_SDA")
	)
	(arc
		(start 356.195884 -224.379536)
		(mid 356.273995 -224.102587)
		(end 356.478332 -223.899984)
		(width 0.0889)
		(layer "B.Cu")
		(net "I3C_SPD_DDRABCD_CPU0_SDA")
	)
	(arc
		(start 356.66553 -225.203258)
		(mid 356.617851 -225.020358)
		(end 356.486968 -224.88398)
		(width 0.0889)
		(layer "B.Cu")
		(net "I3C_SPD_DDRABCD_CPU0_SDA")
	)
	(arc
		(start 349.055436 -219.18168)
		(mid 348.781237 -219.257515)
		(end 348.504764 -219.190316)
		(width 0.0889)
		(layer "B.Cu")
		(net "I3C_SPD_DDRABCD_CPU0_SDA")
	)
	(arc
		(start 345.670632 -219.18168)
		(mid 345.483434 -219.131537)
		(end 345.296236 -219.18168)
		(width 0.0889)
		(layer "B.Cu")
		(net "I3C_SPD_DDRABCD_CPU0_SDA")
	)
	(arc
		(start 335.98993 -217.064336)
		(mid 335.942251 -216.881436)
		(end 335.811368 -216.745058)
		(width 0.0889)
		(layer "B.Cu")
		(net "I3C_SPD_DDRABCD_CPU0_SDA")
	)
	(arc
		(start 349.429832 -219.18168)
		(mid 349.242634 -219.131537)
		(end 349.055436 -219.18168)
		(width 0.0889)
		(layer "B.Cu")
		(net "I3C_SPD_DDRABCD_CPU0_SDA")
	)
	(arc
		(start 356.478332 -223.899984)
		(mid 356.613265 -223.76663)
		(end 356.66553 -223.584262)
		(width 0.0889)
		(layer "B.Cu")
		(net "I3C_SPD_DDRABCD_CPU0_SDA")
	)
	(arc
		(start 335.790286 -216.732866)
		(mid 335.592058 -216.527018)
		(end 335.519776 -216.25052)
		(width 0.0889)
		(layer "B.Cu")
		(net "I3C_SPD_DDRABCD_CPU0_SDA")
	)
	(arc
		(start 341.537036 -219.18168)
		(mid 341.262837 -219.257515)
		(end 340.986364 -219.190316)
		(width 0.0889)
		(layer "B.Cu")
		(net "I3C_SPD_DDRABCD_CPU0_SDA")
	)
	(segment
		(start 358.640634 -230.900478)
		(end 358.640634 -231.436418)
		(width 0.12954)
		(layer "F.Cu")
		(net "I3C_SPD_DDRABCD_CPU0_SCL")
	)
	(via
		(at 358.640634 -230.900478)
		(size 0.4572)
		(drill 0.2032)
		(layers "F.Cu" "B.Cu")
		(net "I3C_SPD_DDRABCD_CPU0_SCL")
	)
	(via
		(at 336.12963 -195.540376)
		(size 0.6604)
		(drill 0.3302)
		(layers "F.Cu" "B.Cu")
		(net "I3C_SPD_DDRABCD_CPU0_SCL")
	)
	(segment
		(start 357.426768 -228.139752)
		(end 357.417878 -228.134672)
		(width 0.0889)
		(layer "B.Cu")
		(net "I3C_SPD_DDRABCD_CPU0_SCL")
	)
	(segment
		(start 348.585536 -219.995496)
		(end 348.575122 -220.001592)
		(width 0.0889)
		(layer "B.Cu")
		(net "I3C_SPD_DDRABCD_CPU0_SCL")
	)
	(segment
		(start 335.34731 -217.562684)
		(end 335.332324 -217.554048)
		(width 0.0889)
		(layer "B.Cu")
		(net "I3C_SPD_DDRABCD_CPU0_SCL")
	)
	(segment
		(start 351.404682 -219.995496)
		(end 351.394268 -220.001592)
		(width 0.0889)
		(layer "B.Cu")
		(net "I3C_SPD_DDRABCD_CPU0_SCL")
	)
	(segment
		(start 334.685132 -216.578434)
		(end 334.391 -216.284302)
		(width 0.0889)
		(layer "B.Cu")
		(net "I3C_SPD_DDRABCD_CPU0_SCL")
	)
	(segment
		(start 358.075484 -229.28834)
		(end 358.075484 -229.272846)
		(width 0.0889)
		(layer "B.Cu")
		(net "I3C_SPD_DDRABCD_CPU0_SCL")
	)
	(segment
		(start 356.017322 -225.69805)
		(end 356.008432 -225.69297)
		(width 0.0889)
		(layer "B.Cu")
		(net "I3C_SPD_DDRABCD_CPU0_SCL")
	)
	(segment
		(start 335.863438 -189.99327)
		(end 335.863438 -188.624972)
		(width 0.12954)
		(layer "B.Cu")
		(net "I3C_SPD_DDRABCD_CPU0_SCL")
	)
	(segment
		(start 345.765882 -219.995496)
		(end 345.755468 -220.001592)
		(width 0.0889)
		(layer "B.Cu")
		(net "I3C_SPD_DDRABCD_CPU0_SCL")
	)
	(segment
		(start 355.547168 -223.256348)
		(end 355.538278 -223.251268)
		(width 0.0889)
		(layer "B.Cu")
		(net "I3C_SPD_DDRABCD_CPU0_SCL")
	)
	(segment
		(start 356.195884 -227.667058)
		(end 356.195884 -227.635054)
		(width 0.0889)
		(layer "B.Cu")
		(net "I3C_SPD_DDRABCD_CPU0_SCL")
	)
	(segment
		(start 334.301338 -215.79586)
		(end 332.276958 -213.77148)
		(width 0.12954)
		(layer "B.Cu")
		(net "I3C_SPD_DDRABCD_CPU0_SCL")
	)
	(segment
		(start 336.12963 -190.259462)
		(end 335.863438 -189.99327)
		(width 0.12954)
		(layer "B.Cu")
		(net "I3C_SPD_DDRABCD_CPU0_SCL")
	)
	(segment
		(start 335.811622 -218.372944)
		(end 335.802732 -218.367864)
		(width 0.0889)
		(layer "B.Cu")
		(net "I3C_SPD_DDRABCD_CPU0_SCL")
	)
	(segment
		(start 351.787968 -220.000576)
		(end 351.779078 -219.995496)
		(width 0.0889)
		(layer "B.Cu")
		(net "I3C_SPD_DDRABCD_CPU0_SCL")
	)
	(segment
		(start 335.990184 -218.702128)
		(end 335.990184 -218.692222)
		(width 0.0889)
		(layer "B.Cu")
		(net "I3C_SPD_DDRABCD_CPU0_SCL")
	)
	(segment
		(start 347.645482 -219.995496)
		(end 347.635068 -220.001592)
		(width 0.0889)
		(layer "B.Cu")
		(net "I3C_SPD_DDRABCD_CPU0_SCL")
	)
	(segment
		(start 338.247482 -219.995496)
		(end 338.237068 -220.001592)
		(width 0.0889)
		(layer "B.Cu")
		(net "I3C_SPD_DDRABCD_CPU0_SCL")
	)
	(segment
		(start 358.366568 -229.767384)
		(end 358.357678 -229.762304)
		(width 0.0889)
		(layer "B.Cu")
		(net "I3C_SPD_DDRABCD_CPU0_SCL")
	)
	(segment
		(start 334.391 -216.284302)
		(end 334.301338 -216.19464)
		(width 0.12954)
		(layer "B.Cu")
		(net "I3C_SPD_DDRABCD_CPU0_SCL")
	)
	(segment
		(start 342.946736 -219.995496)
		(end 342.936322 -220.001592)
		(width 0.0889)
		(layer "B.Cu")
		(net "I3C_SPD_DDRABCD_CPU0_SCL")
	)
	(segment
		(start 334.871568 -216.745058)
		(end 334.862678 -216.739978)
		(width 0.0889)
		(layer "B.Cu")
		(net "I3C_SPD_DDRABCD_CPU0_SCL")
	)
	(segment
		(start 354.143564 -222.445834)
		(end 354.128832 -222.437198)
		(width 0.0889)
		(layer "B.Cu")
		(net "I3C_SPD_DDRABCD_CPU0_SCL")
	)
	(segment
		(start 346.705936 -219.995496)
		(end 346.695522 -220.001592)
		(width 0.0889)
		(layer "B.Cu")
		(net "I3C_SPD_DDRABCD_CPU0_SCL")
	)
	(segment
		(start 353.667568 -221.628462)
		(end 353.658678 -221.623382)
		(width 0.0889)
		(layer "B.Cu")
		(net "I3C_SPD_DDRABCD_CPU0_SCL")
	)
	(segment
		(start 350.465136 -219.995496)
		(end 350.454722 -220.001592)
		(width 0.0889)
		(layer "B.Cu")
		(net "I3C_SPD_DDRABCD_CPU0_SCL")
	)
	(segment
		(start 339.187536 -219.995496)
		(end 339.177122 -220.001592)
		(width 0.0889)
		(layer "B.Cu")
		(net "I3C_SPD_DDRABCD_CPU0_SCL")
	)
	(segment
		(start 357.896922 -228.953568)
		(end 357.888032 -228.948488)
		(width 0.0889)
		(layer "B.Cu")
		(net "I3C_SPD_DDRABCD_CPU0_SCL")
	)
	(segment
		(start 355.256084 -222.783654)
		(end 355.256084 -222.761556)
		(width 0.0889)
		(layer "B.Cu")
		(net "I3C_SPD_DDRABCD_CPU0_SCL")
	)
	(segment
		(start 335.802732 -218.367864)
		(end 335.79054 -218.360752)
		(width 0.0889)
		(layer "B.Cu")
		(net "I3C_SPD_DDRABCD_CPU0_SCL")
	)
	(segment
		(start 336.12963 -195.540376)
		(end 336.12963 -190.259462)
		(width 0.12954)
		(layer "B.Cu")
		(net "I3C_SPD_DDRABCD_CPU0_SCL")
	)
	(segment
		(start 357.043482 -228.134672)
		(end 357.02875 -228.143308)
		(width 0.0889)
		(layer "B.Cu")
		(net "I3C_SPD_DDRABCD_CPU0_SCL")
	)
	(segment
		(start 343.886282 -219.995496)
		(end 343.875868 -220.001592)
		(width 0.0889)
		(layer "B.Cu")
		(net "I3C_SPD_DDRABCD_CPU0_SCL")
	)
	(segment
		(start 358.640634 -230.900478)
		(end 358.55783 -230.20528)
		(width 0.0889)
		(layer "B.Cu")
		(net "I3C_SPD_DDRABCD_CPU0_SCL")
	)
	(segment
		(start 335.05013 -217.086434)
		(end 335.05013 -217.064336)
		(width 0.0889)
		(layer "B.Cu")
		(net "I3C_SPD_DDRABCD_CPU0_SCL")
	)
	(segment
		(start 355.547168 -224.88398)
		(end 355.538278 -224.8789)
		(width 0.0889)
		(layer "B.Cu")
		(net "I3C_SPD_DDRABCD_CPU0_SCL")
	)
	(segment
		(start 349.525082 -219.995496)
		(end 349.514668 -220.001592)
		(width 0.0889)
		(layer "B.Cu")
		(net "I3C_SPD_DDRABCD_CPU0_SCL")
	)
	(segment
		(start 341.067136 -219.995496)
		(end 341.056722 -220.001592)
		(width 0.0889)
		(layer "B.Cu")
		(net "I3C_SPD_DDRABCD_CPU0_SCL")
	)
	(segment
		(start 340.127082 -219.995496)
		(end 340.116668 -220.001592)
		(width 0.0889)
		(layer "B.Cu")
		(net "I3C_SPD_DDRABCD_CPU0_SCL")
	)
	(segment
		(start 335.863438 -188.624972)
		(end 336.094832 -188.393578)
		(width 0.12954)
		(layer "B.Cu")
		(net "I3C_SPD_DDRABCD_CPU0_SCL")
	)
	(segment
		(start 356.66553 -226.83978)
		(end 356.66553 -226.822508)
		(width 0.0889)
		(layer "B.Cu")
		(net "I3C_SPD_DDRABCD_CPU0_SCL")
	)
	(segment
		(start 344.826336 -219.995496)
		(end 344.815922 -220.001592)
		(width 0.0889)
		(layer "B.Cu")
		(net "I3C_SPD_DDRABCD_CPU0_SCL")
	)
	(segment
		(start 353.197922 -220.814646)
		(end 353.189032 -220.809566)
		(width 0.0889)
		(layer "B.Cu")
		(net "I3C_SPD_DDRABCD_CPU0_SCL")
	)
	(segment
		(start 356.195884 -226.027234)
		(end 356.195884 -226.017328)
		(width 0.0889)
		(layer "B.Cu")
		(net "I3C_SPD_DDRABCD_CPU0_SCL")
	)
	(segment
		(start 332.276958 -203.905104)
		(end 336.12963 -200.052432)
		(width 0.12954)
		(layer "B.Cu")
		(net "I3C_SPD_DDRABCD_CPU0_SCL")
	)
	(segment
		(start 336.281522 -219.18676)
		(end 336.272632 -219.18168)
		(width 0.0889)
		(layer "B.Cu")
		(net "I3C_SPD_DDRABCD_CPU0_SCL")
	)
	(segment
		(start 353.376484 -221.149418)
		(end 353.376484 -221.133924)
		(width 0.0889)
		(layer "B.Cu")
		(net "I3C_SPD_DDRABCD_CPU0_SCL")
	)
	(segment
		(start 355.256084 -224.404936)
		(end 355.256084 -224.373948)
		(width 0.0889)
		(layer "B.Cu")
		(net "I3C_SPD_DDRABCD_CPU0_SCL")
	)
	(segment
		(start 355.077522 -222.442278)
		(end 355.068632 -222.437198)
		(width 0.0889)
		(layer "B.Cu")
		(net "I3C_SPD_DDRABCD_CPU0_SCL")
	)
	(segment
		(start 332.276958 -213.77148)
		(end 332.276958 -203.905104)
		(width 0.12954)
		(layer "B.Cu")
		(net "I3C_SPD_DDRABCD_CPU0_SCL")
	)
	(segment
		(start 336.460084 -219.515944)
		(end 336.460084 -219.506038)
		(width 0.0889)
		(layer "B.Cu")
		(net "I3C_SPD_DDRABCD_CPU0_SCL")
	)
	(segment
		(start 351.96653 -220.327474)
		(end 351.96653 -220.319854)
		(width 0.0889)
		(layer "B.Cu")
		(net "I3C_SPD_DDRABCD_CPU0_SCL")
	)
	(segment
		(start 357.888032 -228.948488)
		(end 357.881936 -228.944932)
		(width 0.0889)
		(layer "B.Cu")
		(net "I3C_SPD_DDRABCD_CPU0_SCL")
	)
	(segment
		(start 355.72573 -225.217482)
		(end 355.72573 -225.203258)
		(width 0.0889)
		(layer "B.Cu")
		(net "I3C_SPD_DDRABCD_CPU0_SCL")
	)
	(segment
		(start 354.128832 -222.437198)
		(end 354.122736 -222.433642)
		(width 0.0889)
		(layer "B.Cu")
		(net "I3C_SPD_DDRABCD_CPU0_SCL")
	)
	(segment
		(start 355.538278 -223.899984)
		(end 355.547168 -223.894904)
		(width 0.0889)
		(layer "B.Cu")
		(net "I3C_SPD_DDRABCD_CPU0_SCL")
	)
	(segment
		(start 342.006682 -219.995496)
		(end 341.996268 -220.001592)
		(width 0.0889)
		(layer "B.Cu")
		(net "I3C_SPD_DDRABCD_CPU0_SCL")
	)
	(segment
		(start 336.12963 -200.052432)
		(end 336.12963 -195.540376)
		(width 0.12954)
		(layer "B.Cu")
		(net "I3C_SPD_DDRABCD_CPU0_SCL")
	)
	(segment
		(start 334.301338 -216.19464)
		(end 334.301338 -215.79586)
		(width 0.12954)
		(layer "B.Cu")
		(net "I3C_SPD_DDRABCD_CPU0_SCL")
	)
	(segment
		(start 336.094832 -187.387738)
		(end 336.094832 -188.393578)
		(width 0.12954)
		(layer "B.Cu")
		(net "I3C_SPD_DDRABCD_CPU0_SCL")
	)
	(arc
		(start 346.140278 -219.995496)
		(mid 345.95308 -219.945353)
		(end 345.765882 -219.995496)
		(width 0.0889)
		(layer "B.Cu")
		(net "I3C_SPD_DDRABCD_CPU0_SCL")
	)
	(arc
		(start 350.839532 -219.995496)
		(mid 350.652334 -219.945353)
		(end 350.465136 -219.995496)
		(width 0.0889)
		(layer "B.Cu")
		(net "I3C_SPD_DDRABCD_CPU0_SCL")
	)
	(arc
		(start 355.538278 -224.8789)
		(mid 355.335455 -224.678669)
		(end 355.256084 -224.404936)
		(width 0.0889)
		(layer "B.Cu")
		(net "I3C_SPD_DDRABCD_CPU0_SCL")
	)
	(arc
		(start 348.019878 -219.995496)
		(mid 347.83268 -219.945353)
		(end 347.645482 -219.995496)
		(width 0.0889)
		(layer "B.Cu")
		(net "I3C_SPD_DDRABCD_CPU0_SCL")
	)
	(arc
		(start 337.307936 -219.995496)
		(mid 337.025234 -220.071272)
		(end 336.742532 -219.995496)
		(width 0.0889)
		(layer "B.Cu")
		(net "I3C_SPD_DDRABCD_CPU0_SCL")
	)
	(arc
		(start 355.256084 -222.761556)
		(mid 355.208405 -222.578656)
		(end 355.077522 -222.442278)
		(width 0.0889)
		(layer "B.Cu")
		(net "I3C_SPD_DDRABCD_CPU0_SCL")
	)
	(arc
		(start 357.60533 -228.45903)
		(mid 357.557651 -228.27613)
		(end 357.426768 -228.139752)
		(width 0.0889)
		(layer "B.Cu")
		(net "I3C_SPD_DDRABCD_CPU0_SCL")
	)
	(arc
		(start 355.72573 -225.203258)
		(mid 355.678051 -225.020358)
		(end 355.547168 -224.88398)
		(width 0.0889)
		(layer "B.Cu")
		(net "I3C_SPD_DDRABCD_CPU0_SCL")
	)
	(arc
		(start 341.056722 -220.001592)
		(mid 340.77829 -220.071438)
		(end 340.501478 -219.995496)
		(width 0.0889)
		(layer "B.Cu")
		(net "I3C_SPD_DDRABCD_CPU0_SCL")
	)
	(arc
		(start 349.899478 -219.995496)
		(mid 349.71228 -219.945353)
		(end 349.525082 -219.995496)
		(width 0.0889)
		(layer "B.Cu")
		(net "I3C_SPD_DDRABCD_CPU0_SCL")
	)
	(arc
		(start 347.635068 -220.001592)
		(mid 347.35689 -220.071315)
		(end 347.080332 -219.995496)
		(width 0.0889)
		(layer "B.Cu")
		(net "I3C_SPD_DDRABCD_CPU0_SCL")
	)
	(arc
		(start 356.478332 -226.506786)
		(mid 356.273997 -226.304181)
		(end 356.195884 -226.027234)
		(width 0.0889)
		(layer "B.Cu")
		(net "I3C_SPD_DDRABCD_CPU0_SCL")
	)
	(arc
		(start 344.815922 -220.001592)
		(mid 344.53749 -220.071438)
		(end 344.260678 -219.995496)
		(width 0.0889)
		(layer "B.Cu")
		(net "I3C_SPD_DDRABCD_CPU0_SCL")
	)
	(arc
		(start 354.122736 -222.433642)
		(mid 353.920149 -222.227291)
		(end 353.84613 -221.94774)
		(width 0.0889)
		(layer "B.Cu")
		(net "I3C_SPD_DDRABCD_CPU0_SCL")
	)
	(arc
		(start 335.52003 -217.878406)
		(mid 335.474026 -217.698469)
		(end 335.34731 -217.562684)
		(width 0.0889)
		(layer "B.Cu")
		(net "I3C_SPD_DDRABCD_CPU0_SCL")
	)
	(arc
		(start 354.694236 -222.437198)
		(mid 354.420037 -222.513033)
		(end 354.143564 -222.445834)
		(width 0.0889)
		(layer "B.Cu")
		(net "I3C_SPD_DDRABCD_CPU0_SCL")
	)
	(arc
		(start 336.272632 -219.18168)
		(mid 336.068297 -218.979075)
		(end 335.990184 -218.702128)
		(width 0.0889)
		(layer "B.Cu")
		(net "I3C_SPD_DDRABCD_CPU0_SCL")
	)
	(arc
		(start 353.84613 -221.94774)
		(mid 353.798451 -221.76484)
		(end 353.667568 -221.628462)
		(width 0.0889)
		(layer "B.Cu")
		(net "I3C_SPD_DDRABCD_CPU0_SCL")
	)
	(arc
		(start 344.260678 -219.995496)
		(mid 344.07348 -219.945353)
		(end 343.886282 -219.995496)
		(width 0.0889)
		(layer "B.Cu")
		(net "I3C_SPD_DDRABCD_CPU0_SCL")
	)
	(arc
		(start 335.332324 -217.554048)
		(mid 335.131042 -217.356561)
		(end 335.05013 -217.086434)
		(width 0.0889)
		(layer "B.Cu")
		(net "I3C_SPD_DDRABCD_CPU0_SCL")
	)
	(arc
		(start 345.200732 -219.995496)
		(mid 345.013534 -219.945353)
		(end 344.826336 -219.995496)
		(width 0.0889)
		(layer "B.Cu")
		(net "I3C_SPD_DDRABCD_CPU0_SCL")
	)
	(arc
		(start 345.755468 -220.001592)
		(mid 345.47729 -220.071315)
		(end 345.200732 -219.995496)
		(width 0.0889)
		(layer "B.Cu")
		(net "I3C_SPD_DDRABCD_CPU0_SCL")
	)
	(arc
		(start 357.417878 -228.134672)
		(mid 357.23068 -228.084529)
		(end 357.043482 -228.134672)
		(width 0.0889)
		(layer "B.Cu")
		(net "I3C_SPD_DDRABCD_CPU0_SCL")
	)
	(arc
		(start 342.381078 -219.995496)
		(mid 342.19388 -219.945353)
		(end 342.006682 -219.995496)
		(width 0.0889)
		(layer "B.Cu")
		(net "I3C_SPD_DDRABCD_CPU0_SCL")
	)
	(arc
		(start 343.321132 -219.995496)
		(mid 343.133934 -219.945353)
		(end 342.946736 -219.995496)
		(width 0.0889)
		(layer "B.Cu")
		(net "I3C_SPD_DDRABCD_CPU0_SCL")
	)
	(arc
		(start 358.075484 -229.272846)
		(mid 358.027805 -229.089946)
		(end 357.896922 -228.953568)
		(width 0.0889)
		(layer "B.Cu")
		(net "I3C_SPD_DDRABCD_CPU0_SCL")
	)
	(arc
		(start 340.501478 -219.995496)
		(mid 340.31428 -219.945353)
		(end 340.127082 -219.995496)
		(width 0.0889)
		(layer "B.Cu")
		(net "I3C_SPD_DDRABCD_CPU0_SCL")
	)
	(arc
		(start 355.538278 -223.251268)
		(mid 355.336996 -223.053781)
		(end 355.256084 -222.783654)
		(width 0.0889)
		(layer "B.Cu")
		(net "I3C_SPD_DDRABCD_CPU0_SCL")
	)
	(arc
		(start 348.575122 -220.001592)
		(mid 348.29669 -220.071438)
		(end 348.019878 -219.995496)
		(width 0.0889)
		(layer "B.Cu")
		(net "I3C_SPD_DDRABCD_CPU0_SCL")
	)
	(arc
		(start 349.514668 -220.001592)
		(mid 349.23649 -220.071315)
		(end 348.959932 -219.995496)
		(width 0.0889)
		(layer "B.Cu")
		(net "I3C_SPD_DDRABCD_CPU0_SCL")
	)
	(arc
		(start 346.695522 -220.001592)
		(mid 346.41709 -220.071438)
		(end 346.140278 -219.995496)
		(width 0.0889)
		(layer "B.Cu")
		(net "I3C_SPD_DDRABCD_CPU0_SCL")
	)
	(arc
		(start 336.742532 -219.995496)
		(mid 336.538197 -219.792891)
		(end 336.460084 -219.515944)
		(width 0.0889)
		(layer "B.Cu")
		(net "I3C_SPD_DDRABCD_CPU0_SCL")
	)
	(arc
		(start 341.441532 -219.995496)
		(mid 341.254334 -219.945353)
		(end 341.067136 -219.995496)
		(width 0.0889)
		(layer "B.Cu")
		(net "I3C_SPD_DDRABCD_CPU0_SCL")
	)
	(arc
		(start 337.682332 -219.995496)
		(mid 337.495134 -219.945353)
		(end 337.307936 -219.995496)
		(width 0.0889)
		(layer "B.Cu")
		(net "I3C_SPD_DDRABCD_CPU0_SCL")
	)
	(arc
		(start 336.460084 -219.506038)
		(mid 336.412405 -219.323138)
		(end 336.281522 -219.18676)
		(width 0.0889)
		(layer "B.Cu")
		(net "I3C_SPD_DDRABCD_CPU0_SCL")
	)
	(arc
		(start 350.454722 -220.001592)
		(mid 350.17629 -220.071438)
		(end 349.899478 -219.995496)
		(width 0.0889)
		(layer "B.Cu")
		(net "I3C_SPD_DDRABCD_CPU0_SCL")
	)
	(arc
		(start 352.249232 -220.809566)
		(mid 352.04416 -220.605887)
		(end 351.96653 -220.327474)
		(width 0.0889)
		(layer "B.Cu")
		(net "I3C_SPD_DDRABCD_CPU0_SCL")
	)
	(arc
		(start 353.189032 -220.809566)
		(mid 353.001834 -220.759423)
		(end 352.814636 -220.809566)
		(width 0.0889)
		(layer "B.Cu")
		(net "I3C_SPD_DDRABCD_CPU0_SCL")
	)
	(arc
		(start 357.02875 -228.143308)
		(mid 356.752309 -228.210474)
		(end 356.478078 -228.134672)
		(width 0.0889)
		(layer "B.Cu")
		(net "I3C_SPD_DDRABCD_CPU0_SCL")
	)
	(arc
		(start 335.79054 -218.360752)
		(mid 335.592312 -218.154904)
		(end 335.52003 -217.878406)
		(width 0.0889)
		(layer "B.Cu")
		(net "I3C_SPD_DDRABCD_CPU0_SCL")
	)
	(arc
		(start 351.779078 -219.995496)
		(mid 351.59188 -219.945353)
		(end 351.404682 -219.995496)
		(width 0.0889)
		(layer "B.Cu")
		(net "I3C_SPD_DDRABCD_CPU0_SCL")
	)
	(arc
		(start 340.116668 -220.001592)
		(mid 339.83849 -220.071315)
		(end 339.561932 -219.995496)
		(width 0.0889)
		(layer "B.Cu")
		(net "I3C_SPD_DDRABCD_CPU0_SCL")
	)
	(arc
		(start 355.547168 -223.894904)
		(mid 355.725765 -223.575626)
		(end 355.547168 -223.256348)
		(width 0.0889)
		(layer "B.Cu")
		(net "I3C_SPD_DDRABCD_CPU0_SCL")
	)
	(arc
		(start 335.990184 -218.692222)
		(mid 335.942505 -218.509322)
		(end 335.811622 -218.372944)
		(width 0.0889)
		(layer "B.Cu")
		(net "I3C_SPD_DDRABCD_CPU0_SCL")
	)
	(arc
		(start 356.66553 -226.822508)
		(mid 356.61326 -226.640143)
		(end 356.478332 -226.506786)
		(width 0.0889)
		(layer "B.Cu")
		(net "I3C_SPD_DDRABCD_CPU0_SCL")
	)
	(arc
		(start 338.621878 -219.995496)
		(mid 338.43468 -219.945353)
		(end 338.247482 -219.995496)
		(width 0.0889)
		(layer "B.Cu")
		(net "I3C_SPD_DDRABCD_CPU0_SCL")
	)
	(arc
		(start 356.008432 -225.69297)
		(mid 355.804951 -225.492166)
		(end 355.72573 -225.217482)
		(width 0.0889)
		(layer "B.Cu")
		(net "I3C_SPD_DDRABCD_CPU0_SCL")
	)
	(arc
		(start 356.478078 -228.134672)
		(mid 356.276796 -227.937185)
		(end 356.195884 -227.667058)
		(width 0.0889)
		(layer "B.Cu")
		(net "I3C_SPD_DDRABCD_CPU0_SCL")
	)
	(arc
		(start 358.357678 -229.762304)
		(mid 358.154855 -229.562073)
		(end 358.075484 -229.28834)
		(width 0.0889)
		(layer "B.Cu")
		(net "I3C_SPD_DDRABCD_CPU0_SCL")
	)
	(arc
		(start 341.996268 -220.001592)
		(mid 341.71809 -220.071315)
		(end 341.441532 -219.995496)
		(width 0.0889)
		(layer "B.Cu")
		(net "I3C_SPD_DDRABCD_CPU0_SCL")
	)
	(arc
		(start 356.195884 -226.017328)
		(mid 356.148205 -225.834428)
		(end 356.017322 -225.69805)
		(width 0.0889)
		(layer "B.Cu")
		(net "I3C_SPD_DDRABCD_CPU0_SCL")
	)
	(arc
		(start 339.561932 -219.995496)
		(mid 339.374734 -219.945353)
		(end 339.187536 -219.995496)
		(width 0.0889)
		(layer "B.Cu")
		(net "I3C_SPD_DDRABCD_CPU0_SCL")
	)
	(arc
		(start 358.55783 -230.20528)
		(mid 358.548343 -230.146307)
		(end 358.54513 -230.086662)
		(width 0.0889)
		(layer "B.Cu")
		(net "I3C_SPD_DDRABCD_CPU0_SCL")
	)
	(arc
		(start 339.177122 -220.001592)
		(mid 338.89869 -220.071438)
		(end 338.621878 -219.995496)
		(width 0.0889)
		(layer "B.Cu")
		(net "I3C_SPD_DDRABCD_CPU0_SCL")
	)
	(arc
		(start 347.080332 -219.995496)
		(mid 346.893134 -219.945353)
		(end 346.705936 -219.995496)
		(width 0.0889)
		(layer "B.Cu")
		(net "I3C_SPD_DDRABCD_CPU0_SCL")
	)
	(arc
		(start 355.068632 -222.437198)
		(mid 354.881434 -222.387055)
		(end 354.694236 -222.437198)
		(width 0.0889)
		(layer "B.Cu")
		(net "I3C_SPD_DDRABCD_CPU0_SCL")
	)
	(arc
		(start 351.394268 -220.001592)
		(mid 351.11609 -220.071315)
		(end 350.839532 -219.995496)
		(width 0.0889)
		(layer "B.Cu")
		(net "I3C_SPD_DDRABCD_CPU0_SCL")
	)
	(arc
		(start 335.05013 -217.064336)
		(mid 335.002451 -216.881436)
		(end 334.871568 -216.745058)
		(width 0.0889)
		(layer "B.Cu")
		(net "I3C_SPD_DDRABCD_CPU0_SCL")
	)
	(arc
		(start 342.936322 -220.001592)
		(mid 342.65789 -220.071438)
		(end 342.381078 -219.995496)
		(width 0.0889)
		(layer "B.Cu")
		(net "I3C_SPD_DDRABCD_CPU0_SCL")
	)
	(arc
		(start 357.881936 -228.944932)
		(mid 357.679349 -228.738581)
		(end 357.60533 -228.45903)
		(width 0.0889)
		(layer "B.Cu")
		(net "I3C_SPD_DDRABCD_CPU0_SCL")
	)
	(arc
		(start 356.195884 -227.635054)
		(mid 356.273995 -227.358105)
		(end 356.478332 -227.155502)
		(width 0.0889)
		(layer "B.Cu")
		(net "I3C_SPD_DDRABCD_CPU0_SCL")
	)
	(arc
		(start 353.376484 -221.133924)
		(mid 353.328805 -220.951024)
		(end 353.197922 -220.814646)
		(width 0.0889)
		(layer "B.Cu")
		(net "I3C_SPD_DDRABCD_CPU0_SCL")
	)
	(arc
		(start 343.875868 -220.001592)
		(mid 343.59769 -220.071315)
		(end 343.321132 -219.995496)
		(width 0.0889)
		(layer "B.Cu")
		(net "I3C_SPD_DDRABCD_CPU0_SCL")
	)
	(arc
		(start 338.237068 -220.001592)
		(mid 337.95889 -220.071315)
		(end 337.682332 -219.995496)
		(width 0.0889)
		(layer "B.Cu")
		(net "I3C_SPD_DDRABCD_CPU0_SCL")
	)
	(arc
		(start 348.959932 -219.995496)
		(mid 348.772734 -219.945353)
		(end 348.585536 -219.995496)
		(width 0.0889)
		(layer "B.Cu")
		(net "I3C_SPD_DDRABCD_CPU0_SCL")
	)
	(arc
		(start 355.256084 -224.373948)
		(mid 355.335454 -224.100214)
		(end 355.538278 -223.899984)
		(width 0.0889)
		(layer "B.Cu")
		(net "I3C_SPD_DDRABCD_CPU0_SCL")
	)
	(arc
		(start 353.658678 -221.623382)
		(mid 353.455855 -221.423151)
		(end 353.376484 -221.149418)
		(width 0.0889)
		(layer "B.Cu")
		(net "I3C_SPD_DDRABCD_CPU0_SCL")
	)
	(arc
		(start 356.478332 -227.155502)
		(mid 356.613265 -227.022148)
		(end 356.66553 -226.83978)
		(width 0.0889)
		(layer "B.Cu")
		(net "I3C_SPD_DDRABCD_CPU0_SCL")
	)
	(arc
		(start 334.862678 -216.739978)
		(mid 334.76521 -216.668759)
		(end 334.685132 -216.578434)
		(width 0.0889)
		(layer "B.Cu")
		(net "I3C_SPD_DDRABCD_CPU0_SCL")
	)
	(arc
		(start 351.96653 -220.319854)
		(mid 351.918851 -220.136954)
		(end 351.787968 -220.000576)
		(width 0.0889)
		(layer "B.Cu")
		(net "I3C_SPD_DDRABCD_CPU0_SCL")
	)
	(arc
		(start 358.54513 -230.086662)
		(mid 358.497451 -229.903762)
		(end 358.366568 -229.767384)
		(width 0.0889)
		(layer "B.Cu")
		(net "I3C_SPD_DDRABCD_CPU0_SCL")
	)
	(arc
		(start 352.814636 -220.809566)
		(mid 352.531934 -220.885308)
		(end 352.249232 -220.809566)
		(width 0.0889)
		(layer "B.Cu")
		(net "I3C_SPD_DDRABCD_CPU0_SCL")
	)
	(via
		(at 294.145716 -153.40711)
		(size 0.6604)
		(drill 0.3302)
		(layers "F.Cu" "B.Cu")
		(net "I3C_SPD_DDRABCD_CPU0_R_SDA")
	)
	(via
		(at 339.775038 -185.077608)
		(size 0.6604)
		(drill 0.3302)
		(layers "F.Cu" "B.Cu")
		(net "I3C_SPD_DDRABCD_CPU0_R_SDA")
	)
	(segment
		(start 294.56888 -152.977342)
		(end 294.56888 -152.827482)
		(width 0.12954)
		(layer "B.Cu")
		(net "I3C_SPD_DDRABCD_CPU0_R_SDA")
	)
	(segment
		(start 320.90868 -166.715948)
		(end 327.563226 -166.715948)
		(width 0.12954)
		(layer "B.Cu")
		(net "I3C_SPD_DDRABCD_CPU0_R_SDA")
	)
	(segment
		(start 294.145716 -153.400506)
		(end 294.145716 -153.40711)
		(width 0.12954)
		(layer "B.Cu")
		(net "I3C_SPD_DDRABCD_CPU0_R_SDA")
	)
	(segment
		(start 290.450778 -153.358088)
		(end 290.450778 -154.544776)
		(width 0.12954)
		(layer "B.Cu")
		(net "I3C_SPD_DDRABCD_CPU0_R_SDA")
	)
	(segment
		(start 290.450778 -154.544776)
		(end 291.60089 -155.694888)
		(width 0.12954)
		(layer "B.Cu")
		(net "I3C_SPD_DDRABCD_CPU0_R_SDA")
	)
	(segment
		(start 292.998398 -153.145998)
		(end 293.891208 -153.145998)
		(width 0.12954)
		(layer "B.Cu")
		(net "I3C_SPD_DDRABCD_CPU0_R_SDA")
	)
	(segment
		(start 309.88762 -155.694888)
		(end 320.90868 -166.715948)
		(width 0.12954)
		(layer "B.Cu")
		(net "I3C_SPD_DDRABCD_CPU0_R_SDA")
	)
	(segment
		(start 294.56888 -152.827482)
		(end 295.040304 -152.356058)
		(width 0.12954)
		(layer "B.Cu")
		(net "I3C_SPD_DDRABCD_CPU0_R_SDA")
	)
	(segment
		(start 292.998398 -153.145998)
		(end 290.662868 -153.145998)
		(width 0.12954)
		(layer "B.Cu")
		(net "I3C_SPD_DDRABCD_CPU0_R_SDA")
	)
	(segment
		(start 290.662868 -153.145998)
		(end 290.450778 -153.358088)
		(width 0.12954)
		(layer "B.Cu")
		(net "I3C_SPD_DDRABCD_CPU0_R_SDA")
	)
	(segment
		(start 327.563226 -166.715948)
		(end 339.775038 -178.92776)
		(width 0.12954)
		(layer "B.Cu")
		(net "I3C_SPD_DDRABCD_CPU0_R_SDA")
	)
	(segment
		(start 294.145716 -153.400506)
		(end 294.56888 -152.977342)
		(width 0.12954)
		(layer "B.Cu")
		(net "I3C_SPD_DDRABCD_CPU0_R_SDA")
	)
	(segment
		(start 339.775038 -185.077608)
		(end 339.775038 -189.580012)
		(width 0.12954)
		(layer "B.Cu")
		(net "I3C_SPD_DDRABCD_CPU0_R_SDA")
	)
	(segment
		(start 295.040304 -152.356058)
		(end 295.873932 -152.356058)
		(width 0.12954)
		(layer "B.Cu")
		(net "I3C_SPD_DDRABCD_CPU0_R_SDA")
	)
	(segment
		(start 339.775038 -189.580012)
		(end 338.998814 -190.356236)
		(width 0.12954)
		(layer "B.Cu")
		(net "I3C_SPD_DDRABCD_CPU0_R_SDA")
	)
	(segment
		(start 339.775038 -178.92776)
		(end 339.775038 -185.077608)
		(width 0.12954)
		(layer "B.Cu")
		(net "I3C_SPD_DDRABCD_CPU0_R_SDA")
	)
	(segment
		(start 291.60089 -155.694888)
		(end 309.88762 -155.694888)
		(width 0.12954)
		(layer "B.Cu")
		(net "I3C_SPD_DDRABCD_CPU0_R_SDA")
	)
	(segment
		(start 293.891208 -153.145998)
		(end 294.145716 -153.400506)
		(width 0.12954)
		(layer "B.Cu")
		(net "I3C_SPD_DDRABCD_CPU0_R_SDA")
	)
	(via
		(at 294.13708 -150.828248)
		(size 0.6604)
		(drill 0.3302)
		(layers "F.Cu" "B.Cu")
		(net "I3C_SPD_DDRABCD_CPU0_R_SCL")
	)
	(via
		(at 337.50123 -186.013344)
		(size 0.6604)
		(drill 0.3302)
		(layers "F.Cu" "B.Cu")
		(net "I3C_SPD_DDRABCD_CPU0_R_SCL")
	)
	(segment
		(start 320.524886 -168.590976)
		(end 326.496426 -168.590976)
		(width 0.12954)
		(layer "B.Cu")
		(net "I3C_SPD_DDRABCD_CPU0_R_SCL")
	)
	(segment
		(start 292.983158 -151.375618)
		(end 290.195508 -151.375618)
		(width 0.12954)
		(layer "B.Cu")
		(net "I3C_SPD_DDRABCD_CPU0_R_SCL")
	)
	(segment
		(start 295.873932 -150.451058)
		(end 295.159176 -150.451058)
		(width 0.12954)
		(layer "B.Cu")
		(net "I3C_SPD_DDRABCD_CPU0_R_SCL")
	)
	(segment
		(start 294.13708 -150.828248)
		(end 293.58971 -151.375618)
		(width 0.12954)
		(layer "B.Cu")
		(net "I3C_SPD_DDRABCD_CPU0_R_SCL")
	)
	(segment
		(start 294.781986 -150.828248)
		(end 294.13708 -150.828248)
		(width 0.12954)
		(layer "B.Cu")
		(net "I3C_SPD_DDRABCD_CPU0_R_SCL")
	)
	(segment
		(start 289.023298 -152.547828)
		(end 289.023298 -155.126944)
		(width 0.12954)
		(layer "B.Cu")
		(net "I3C_SPD_DDRABCD_CPU0_R_SCL")
	)
	(segment
		(start 295.159176 -150.451058)
		(end 294.781986 -150.828248)
		(width 0.12954)
		(layer "B.Cu")
		(net "I3C_SPD_DDRABCD_CPU0_R_SCL")
	)
	(segment
		(start 290.195508 -151.375618)
		(end 289.023298 -152.547828)
		(width 0.12954)
		(layer "B.Cu")
		(net "I3C_SPD_DDRABCD_CPU0_R_SCL")
	)
	(segment
		(start 337.97494 -185.539634)
		(end 337.50123 -186.013344)
		(width 0.12954)
		(layer "B.Cu")
		(net "I3C_SPD_DDRABCD_CPU0_R_SCL")
	)
	(segment
		(start 336.894932 -186.619642)
		(end 336.894932 -187.387738)
		(width 0.12954)
		(layer "B.Cu")
		(net "I3C_SPD_DDRABCD_CPU0_R_SCL")
	)
	(segment
		(start 326.496426 -168.590976)
		(end 337.97494 -180.06949)
		(width 0.12954)
		(layer "B.Cu")
		(net "I3C_SPD_DDRABCD_CPU0_R_SCL")
	)
	(segment
		(start 308.954678 -157.020768)
		(end 320.524886 -168.590976)
		(width 0.12954)
		(layer "B.Cu")
		(net "I3C_SPD_DDRABCD_CPU0_R_SCL")
	)
	(segment
		(start 337.50123 -186.013344)
		(end 336.894932 -186.619642)
		(width 0.12954)
		(layer "B.Cu")
		(net "I3C_SPD_DDRABCD_CPU0_R_SCL")
	)
	(segment
		(start 337.97494 -180.06949)
		(end 337.97494 -185.539634)
		(width 0.12954)
		(layer "B.Cu")
		(net "I3C_SPD_DDRABCD_CPU0_R_SCL")
	)
	(segment
		(start 290.917122 -157.020768)
		(end 308.954678 -157.020768)
		(width 0.12954)
		(layer "B.Cu")
		(net "I3C_SPD_DDRABCD_CPU0_R_SCL")
	)
	(segment
		(start 289.023298 -155.126944)
		(end 290.917122 -157.020768)
		(width 0.12954)
		(layer "B.Cu")
		(net "I3C_SPD_DDRABCD_CPU0_R_SCL")
	)
	(segment
		(start 293.58971 -151.375618)
		(end 292.983158 -151.375618)
		(width 0.12954)
		(layer "B.Cu")
		(net "I3C_SPD_DDRABCD_CPU0_R_SCL")
	)
	(segment
		(start 284.784292 -318.016636)
		(end 284.354778 -317.587122)
		(width 0.12954)
		(layer "F.Cu")
		(net "I3C_SPD_DDRABCD_CPU0_LVC1_SDA")
	)
	(segment
		(start 286.255714 -318.016636)
		(end 284.784292 -318.016636)
		(width 0.12954)
		(layer "F.Cu")
		(net "I3C_SPD_DDRABCD_CPU0_LVC1_SDA")
	)
	(segment
		(start 297.098974 -317.587122)
		(end 298.713144 -317.587122)
		(width 0.1016)
		(layer "F.Cu")
		(net "I3C_SPD_DDRABCD_CPU0_LVC1_SDA")
	)
	(segment
		(start 299.740066 -317.587122)
		(end 300.16958 -318.016636)
		(width 0.12954)
		(layer "F.Cu")
		(net "I3C_SPD_DDRABCD_CPU0_LVC1_SDA")
	)
	(segment
		(start 301.343314 -318.016636)
		(end 303.097692 -318.016636)
		(width 0.12954)
		(layer "F.Cu")
		(net "I3C_SPD_DDRABCD_CPU0_LVC1_SDA")
	)
	(segment
		(start 295.940226 -317.587122)
		(end 297.098974 -317.587122)
		(width 0.12954)
		(layer "F.Cu")
		(net "I3C_SPD_DDRABCD_CPU0_LVC1_SDA")
	)
	(segment
		(start 303.097692 -318.016636)
		(end 303.527206 -317.587122)
		(width 0.12954)
		(layer "F.Cu")
		(net "I3C_SPD_DDRABCD_CPU0_LVC1_SDA")
	)
	(segment
		(start 281.41168 -317.025528)
		(end 280.71318 -317.025528)
		(width 0.12954)
		(layer "F.Cu")
		(net "I3C_SPD_DDRABCD_CPU0_LVC1_SDA")
	)
	(segment
		(start 304.642774 -317.587122)
		(end 306.256944 -317.587122)
		(width 0.1016)
		(layer "F.Cu")
		(net "I3C_SPD_DDRABCD_CPU0_LVC1_SDA")
	)
	(segment
		(start 266.923774 -317.587122)
		(end 268.537944 -317.587122)
		(width 0.1016)
		(layer "F.Cu")
		(net "I3C_SPD_DDRABCD_CPU0_LVC1_SDA")
	)
	(segment
		(start 263.624314 -318.016636)
		(end 265.254232 -318.016636)
		(width 0.12954)
		(layer "F.Cu")
		(net "I3C_SPD_DDRABCD_CPU0_LVC1_SDA")
	)
	(segment
		(start 260.994144 -317.587122)
		(end 259.379974 -317.587122)
		(width 0.1016)
		(layer "F.Cu")
		(net "I3C_SPD_DDRABCD_CPU0_LVC1_SDA")
	)
	(segment
		(start 292.277292 -318.016636)
		(end 291.847778 -317.587122)
		(width 0.12954)
		(layer "F.Cu")
		(net "I3C_SPD_DDRABCD_CPU0_LVC1_SDA")
	)
	(segment
		(start 254.630428 -318.016636)
		(end 256.080514 -318.016636)
		(width 0.12954)
		(layer "F.Cu")
		(net "I3C_SPD_DDRABCD_CPU0_LVC1_SDA")
	)
	(segment
		(start 276.081744 -317.587122)
		(end 274.467574 -317.587122)
		(width 0.1016)
		(layer "F.Cu")
		(net "I3C_SPD_DDRABCD_CPU0_LVC1_SDA")
	)
	(segment
		(start 287.995106 -317.587122)
		(end 287.565592 -318.016636)
		(width 0.12954)
		(layer "F.Cu")
		(net "I3C_SPD_DDRABCD_CPU0_LVC1_SDA")
	)
	(segment
		(start 272.465292 -318.016636)
		(end 271.168114 -318.016636)
		(width 0.12954)
		(layer "F.Cu")
		(net "I3C_SPD_DDRABCD_CPU0_LVC1_SDA")
	)
	(segment
		(start 259.379974 -317.587122)
		(end 258.186174 -317.587122)
		(width 0.12954)
		(layer "F.Cu")
		(net "I3C_SPD_DDRABCD_CPU0_LVC1_SDA")
	)
	(segment
		(start 258.186174 -317.587122)
		(end 257.75666 -318.016636)
		(width 0.12954)
		(layer "F.Cu")
		(net "I3C_SPD_DDRABCD_CPU0_LVC1_SDA")
	)
	(segment
		(start 276.770338 -317.587122)
		(end 276.081744 -317.587122)
		(width 0.12954)
		(layer "F.Cu")
		(net "I3C_SPD_DDRABCD_CPU0_LVC1_SDA")
	)
	(segment
		(start 277.199852 -318.016636)
		(end 276.770338 -317.587122)
		(width 0.12954)
		(layer "F.Cu")
		(net "I3C_SPD_DDRABCD_CPU0_LVC1_SDA")
	)
	(segment
		(start 268.537944 -317.587122)
		(end 269.595346 -317.587122)
		(width 0.12954)
		(layer "F.Cu")
		(net "I3C_SPD_DDRABCD_CPU0_LVC1_SDA")
	)
	(segment
		(start 284.354778 -317.587122)
		(end 283.625544 -317.587122)
		(width 0.12954)
		(layer "F.Cu")
		(net "I3C_SPD_DDRABCD_CPU0_LVC1_SDA")
	)
	(segment
		(start 265.254232 -318.016636)
		(end 265.683746 -317.587122)
		(width 0.12954)
		(layer "F.Cu")
		(net "I3C_SPD_DDRABCD_CPU0_LVC1_SDA")
	)
	(segment
		(start 283.625544 -317.587122)
		(end 281.973274 -317.587122)
		(width 0.1016)
		(layer "F.Cu")
		(net "I3C_SPD_DDRABCD_CPU0_LVC1_SDA")
	)
	(segment
		(start 291.847778 -317.587122)
		(end 291.169344 -317.587122)
		(width 0.12954)
		(layer "F.Cu")
		(net "I3C_SPD_DDRABCD_CPU0_LVC1_SDA")
	)
	(segment
		(start 261.570724 -317.587122)
		(end 260.994144 -317.587122)
		(width 0.12954)
		(layer "F.Cu")
		(net "I3C_SPD_DDRABCD_CPU0_LVC1_SDA")
	)
	(segment
		(start 270.02486 -318.016636)
		(end 271.168114 -318.016636)
		(width 0.12954)
		(layer "F.Cu")
		(net "I3C_SPD_DDRABCD_CPU0_LVC1_SDA")
	)
	(segment
		(start 300.16958 -318.016636)
		(end 301.343314 -318.016636)
		(width 0.12954)
		(layer "F.Cu")
		(net "I3C_SPD_DDRABCD_CPU0_LVC1_SDA")
	)
	(segment
		(start 257.75666 -318.016636)
		(end 256.080514 -318.016636)
		(width 0.12954)
		(layer "F.Cu")
		(net "I3C_SPD_DDRABCD_CPU0_LVC1_SDA")
	)
	(segment
		(start 287.565592 -318.016636)
		(end 286.255714 -318.016636)
		(width 0.12954)
		(layer "F.Cu")
		(net "I3C_SPD_DDRABCD_CPU0_LVC1_SDA")
	)
	(segment
		(start 291.169344 -317.587122)
		(end 289.555174 -317.587122)
		(width 0.1016)
		(layer "F.Cu")
		(net "I3C_SPD_DDRABCD_CPU0_LVC1_SDA")
	)
	(segment
		(start 293.799514 -318.016636)
		(end 295.510712 -318.016636)
		(width 0.12954)
		(layer "F.Cu")
		(net "I3C_SPD_DDRABCD_CPU0_LVC1_SDA")
	)
	(segment
		(start 272.894806 -317.587122)
		(end 272.465292 -318.016636)
		(width 0.12954)
		(layer "F.Cu")
		(net "I3C_SPD_DDRABCD_CPU0_LVC1_SDA")
	)
	(segment
		(start 278.711914 -318.016636)
		(end 277.199852 -318.016636)
		(width 0.12954)
		(layer "F.Cu")
		(net "I3C_SPD_DDRABCD_CPU0_LVC1_SDA")
	)
	(segment
		(start 293.799514 -318.016636)
		(end 292.277292 -318.016636)
		(width 0.12954)
		(layer "F.Cu")
		(net "I3C_SPD_DDRABCD_CPU0_LVC1_SDA")
	)
	(segment
		(start 280.71318 -317.025528)
		(end 279.722072 -318.016636)
		(width 0.12954)
		(layer "F.Cu")
		(net "I3C_SPD_DDRABCD_CPU0_LVC1_SDA")
	)
	(segment
		(start 289.555174 -317.587122)
		(end 287.995106 -317.587122)
		(width 0.12954)
		(layer "F.Cu")
		(net "I3C_SPD_DDRABCD_CPU0_LVC1_SDA")
	)
	(segment
		(start 306.256944 -317.587122)
		(end 307.325776 -317.587122)
		(width 0.12954)
		(layer "F.Cu")
		(net "I3C_SPD_DDRABCD_CPU0_LVC1_SDA")
	)
	(segment
		(start 274.467574 -317.587122)
		(end 272.894806 -317.587122)
		(width 0.12954)
		(layer "F.Cu")
		(net "I3C_SPD_DDRABCD_CPU0_LVC1_SDA")
	)
	(segment
		(start 265.683746 -317.587122)
		(end 266.923774 -317.587122)
		(width 0.12954)
		(layer "F.Cu")
		(net "I3C_SPD_DDRABCD_CPU0_LVC1_SDA")
	)
	(segment
		(start 254.50038 -317.886588)
		(end 254.630428 -318.016636)
		(width 0.12954)
		(layer "F.Cu")
		(net "I3C_SPD_DDRABCD_CPU0_LVC1_SDA")
	)
	(segment
		(start 281.973274 -317.587122)
		(end 281.41168 -317.025528)
		(width 0.12954)
		(layer "F.Cu")
		(net "I3C_SPD_DDRABCD_CPU0_LVC1_SDA")
	)
	(segment
		(start 307.325776 -317.587122)
		(end 307.75529 -318.016636)
		(width 0.12954)
		(layer "F.Cu")
		(net "I3C_SPD_DDRABCD_CPU0_LVC1_SDA")
	)
	(segment
		(start 307.75529 -318.016636)
		(end 308.887114 -318.016636)
		(width 0.12954)
		(layer "F.Cu")
		(net "I3C_SPD_DDRABCD_CPU0_LVC1_SDA")
	)
	(segment
		(start 298.713144 -317.587122)
		(end 299.740066 -317.587122)
		(width 0.12954)
		(layer "F.Cu")
		(net "I3C_SPD_DDRABCD_CPU0_LVC1_SDA")
	)
	(segment
		(start 279.722072 -318.016636)
		(end 278.711914 -318.016636)
		(width 0.12954)
		(layer "F.Cu")
		(net "I3C_SPD_DDRABCD_CPU0_LVC1_SDA")
	)
	(segment
		(start 262.000238 -318.016636)
		(end 261.570724 -317.587122)
		(width 0.12954)
		(layer "F.Cu")
		(net "I3C_SPD_DDRABCD_CPU0_LVC1_SDA")
	)
	(segment
		(start 303.527206 -317.587122)
		(end 304.642774 -317.587122)
		(width 0.12954)
		(layer "F.Cu")
		(net "I3C_SPD_DDRABCD_CPU0_LVC1_SDA")
	)
	(segment
		(start 295.510712 -318.016636)
		(end 295.940226 -317.587122)
		(width 0.12954)
		(layer "F.Cu")
		(net "I3C_SPD_DDRABCD_CPU0_LVC1_SDA")
	)
	(segment
		(start 269.595346 -317.587122)
		(end 270.02486 -318.016636)
		(width 0.12954)
		(layer "F.Cu")
		(net "I3C_SPD_DDRABCD_CPU0_LVC1_SDA")
	)
	(segment
		(start 263.624314 -318.016636)
		(end 262.000238 -318.016636)
		(width 0.12954)
		(layer "F.Cu")
		(net "I3C_SPD_DDRABCD_CPU0_LVC1_SDA")
	)
	(via
		(at 292.13556 -155.031948)
		(size 0.762)
		(drill 0.254)
		(layers "F.Cu" "B.Cu")
		(net "I3C_SPD_DDRABCD_CPU0_LVC1_SDA")
	)
	(via
		(at 254.50038 -317.886588)
		(size 0.4572)
		(drill 0.2032)
		(layers "F.Cu" "B.Cu")
		(net "I3C_SPD_DDRABCD_CPU0_LVC1_SDA")
	)
	(segment
		(start 291.875718 -155.031948)
		(end 291.186108 -154.342338)
		(width 0.12954)
		(layer "B.Cu")
		(net "I3C_SPD_DDRABCD_CPU0_LVC1_SDA")
	)
	(segment
		(start 291.186108 -154.342338)
		(end 291.186108 -153.944828)
		(width 0.12954)
		(layer "B.Cu")
		(net "I3C_SPD_DDRABCD_CPU0_LVC1_SDA")
	)
	(segment
		(start 292.13556 -155.031948)
		(end 291.875718 -155.031948)
		(width 0.12954)
		(layer "B.Cu")
		(net "I3C_SPD_DDRABCD_CPU0_LVC1_SDA")
	)
	(segment
		(start 260.66242 -180.010562)
		(end 260.66242 -189.418722)
		(width 0.127)
		(layer "In2.Cu")
		(net "I3C_SPD_DDRABCD_CPU0_LVC1_SDA")
	)
	(segment
		(start 257.82778 -252.242828)
		(end 255.5367 -254.533908)
		(width 0.127)
		(layer "In2.Cu")
		(net "I3C_SPD_DDRABCD_CPU0_LVC1_SDA")
	)
	(segment
		(start 255.5367 -254.533908)
		(end 255.5367 -256.036572)
		(width 0.127)
		(layer "In2.Cu")
		(net "I3C_SPD_DDRABCD_CPU0_LVC1_SDA")
	)
	(segment
		(start 255.5367 -256.036572)
		(end 257.81762 -258.317492)
		(width 0.127)
		(layer "In2.Cu")
		(net "I3C_SPD_DDRABCD_CPU0_LVC1_SDA")
	)
	(segment
		(start 291.05606 -153.789888)
		(end 284.62986 -153.789888)
		(width 0.127)
		(layer "In2.Cu")
		(net "I3C_SPD_DDRABCD_CPU0_LVC1_SDA")
	)
	(segment
		(start 283.93771 -156.735272)
		(end 260.66242 -180.010562)
		(width 0.127)
		(layer "In2.Cu")
		(net "I3C_SPD_DDRABCD_CPU0_LVC1_SDA")
	)
	(segment
		(start 254.630428 -318.016636)
		(end 254.50038 -317.886588)
		(width 0.127)
		(layer "In2.Cu")
		(net "I3C_SPD_DDRABCD_CPU0_LVC1_SDA")
	)
	(segment
		(start 257.82778 -192.253362)
		(end 257.82778 -252.242828)
		(width 0.127)
		(layer "In2.Cu")
		(net "I3C_SPD_DDRABCD_CPU0_LVC1_SDA")
	)
	(segment
		(start 292.13556 -155.031948)
		(end 292.13556 -154.869388)
		(width 0.127)
		(layer "In2.Cu")
		(net "I3C_SPD_DDRABCD_CPU0_LVC1_SDA")
	)
	(segment
		(start 257.81762 -317.437008)
		(end 257.237992 -318.016636)
		(width 0.127)
		(layer "In2.Cu")
		(net "I3C_SPD_DDRABCD_CPU0_LVC1_SDA")
	)
	(segment
		(start 284.62986 -153.789888)
		(end 283.93771 -154.482038)
		(width 0.127)
		(layer "In2.Cu")
		(net "I3C_SPD_DDRABCD_CPU0_LVC1_SDA")
	)
	(segment
		(start 260.66242 -189.418722)
		(end 257.82778 -192.253362)
		(width 0.127)
		(layer "In2.Cu")
		(net "I3C_SPD_DDRABCD_CPU0_LVC1_SDA")
	)
	(segment
		(start 283.93771 -154.482038)
		(end 283.93771 -156.735272)
		(width 0.127)
		(layer "In2.Cu")
		(net "I3C_SPD_DDRABCD_CPU0_LVC1_SDA")
	)
	(segment
		(start 257.81762 -258.317492)
		(end 257.81762 -317.437008)
		(width 0.127)
		(layer "In2.Cu")
		(net "I3C_SPD_DDRABCD_CPU0_LVC1_SDA")
	)
	(segment
		(start 257.237992 -318.016636)
		(end 254.630428 -318.016636)
		(width 0.127)
		(layer "In2.Cu")
		(net "I3C_SPD_DDRABCD_CPU0_LVC1_SDA")
	)
	(segment
		(start 292.13556 -154.869388)
		(end 291.05606 -153.789888)
		(width 0.127)
		(layer "In2.Cu")
		(net "I3C_SPD_DDRABCD_CPU0_LVC1_SDA")
	)
	(via
		(at 276.929342 -316.6872)
		(size 0.4572)
		(drill 0.2032)
		(layers "F.Cu" "B.Cu")
		(net "I3C_SPD_DDRABCD_CPU0_LVC1_SCL")
	)
	(via
		(at 288.4805 -318.940688)
		(size 0.508)
		(drill 0.254)
		(layers "F.Cu" "B.Cu")
		(net "I3C_SPD_DDRABCD_CPU0_LVC1_SCL")
	)
	(via
		(at 258.5466 -316.898528)
		(size 0.4572)
		(drill 0.2032)
		(layers "F.Cu" "B.Cu")
		(net "I3C_SPD_DDRABCD_CPU0_LVC1_SCL")
	)
	(via
		(at 289.791648 -152.960578)
		(size 0.6604)
		(drill 0.3302)
		(layers "F.Cu" "B.Cu")
		(net "I3C_SPD_DDRABCD_CPU0_LVC1_SCL")
	)
	(via
		(at 289.737038 -154.625548)
		(size 0.508)
		(drill 0.254)
		(layers "F.Cu" "B.Cu")
		(net "I3C_SPD_DDRABCD_CPU0_LVC1_SCL")
	)
	(segment
		(start 300.254924 -316.197742)
		(end 299.609002 -316.843664)
		(width 0.12954)
		(layer "B.Cu")
		(net "I3C_SPD_DDRABCD_CPU0_LVC1_SCL")
	)
	(segment
		(start 295.939972 -316.803278)
		(end 297.36669 -316.803278)
		(width 0.12954)
		(layer "B.Cu")
		(net "I3C_SPD_DDRABCD_CPU0_LVC1_SCL")
	)
	(segment
		(start 302.667924 -316.197742)
		(end 300.254924 -316.197742)
		(width 0.12954)
		(layer "B.Cu")
		(net "I3C_SPD_DDRABCD_CPU0_LVC1_SCL")
	)
	(segment
		(start 299.59808 -314.401708)
		(end 299.59808 -316.832742)
		(width 0.12954)
		(layer "B.Cu")
		(net "I3C_SPD_DDRABCD_CPU0_LVC1_SCL")
	)
	(segment
		(start 256.95148 -316.705488)
		(end 256.49174 -317.165228)
		(width 0.12954)
		(layer "B.Cu")
		(net "I3C_SPD_DDRABCD_CPU0_LVC1_SCL")
	)
	(segment
		(start 291.917628 -316.083696)
		(end 291.917628 -316.646052)
		(width 0.12954)
		(layer "B.Cu")
		(net "I3C_SPD_DDRABCD_CPU0_LVC1_SCL")
	)
	(segment
		(start 256.49174 -317.165228)
		(end 256.49174 -318.482726)
		(width 0.12954)
		(layer "B.Cu")
		(net "I3C_SPD_DDRABCD_CPU0_LVC1_SCL")
	)
	(segment
		(start 261.91972 -316.024006)
		(end 261.561834 -315.66612)
		(width 0.12954)
		(layer "B.Cu")
		(net "I3C_SPD_DDRABCD_CPU0_LVC1_SCL")
	)
	(segment
		(start 305.005486 -316.25286)
		(end 305.005486 -315.776864)
		(width 0.12954)
		(layer "B.Cu")
		(net "I3C_SPD_DDRABCD_CPU0_LVC1_SCL")
	)
	(segment
		(start 273.355816 -315.734446)
		(end 276.808184 -315.734446)
		(width 0.12954)
		(layer "B.Cu")
		(net "I3C_SPD_DDRABCD_CPU0_LVC1_SCL")
	)
	(segment
		(start 262.467852 -317.881762)
		(end 262.13562 -317.881762)
		(width 0.12954)
		(layer "B.Cu")
		(net "I3C_SPD_DDRABCD_CPU0_LVC1_SCL")
	)
	(segment
		(start 288.33191 -318.322198)
		(end 288.33191 -317.909448)
		(width 0.12954)
		(layer "B.Cu")
		(net "I3C_SPD_DDRABCD_CPU0_LVC1_SCL")
	)
	(segment
		(start 271.580864 -317.824358)
		(end 269.618714 -315.862208)
		(width 0.12954)
		(layer "B.Cu")
		(net "I3C_SPD_DDRABCD_CPU0_LVC1_SCL")
	)
	(segment
		(start 293.993824 -317.647828)
		(end 295.095422 -317.647828)
		(width 0.12954)
		(layer "B.Cu")
		(net "I3C_SPD_DDRABCD_CPU0_LVC1_SCL")
	)
	(segment
		(start 288.27603 -317.434722)
		(end 288.33191 -317.378842)
		(width 0.12954)
		(layer "B.Cu")
		(net "I3C_SPD_DDRABCD_CPU0_LVC1_SCL")
	)
	(segment
		(start 288.33191 -317.378842)
		(end 288.33191 -316.445138)
		(width 0.12954)
		(layer "B.Cu")
		(net "I3C_SPD_DDRABCD_CPU0_LVC1_SCL")
	)
	(segment
		(start 263.631426 -316.718188)
		(end 262.467852 -317.881762)
		(width 0.12954)
		(layer "B.Cu")
		(net "I3C_SPD_DDRABCD_CPU0_LVC1_SCL")
	)
	(segment
		(start 304.912776 -316.861444)
		(end 304.912776 -316.34557)
		(width 0.12954)
		(layer "B.Cu")
		(net "I3C_SPD_DDRABCD_CPU0_LVC1_SCL")
	)
	(segment
		(start 272.597626 -316.492636)
		(end 273.355816 -315.734446)
		(width 0.12954)
		(layer "B.Cu")
		(net "I3C_SPD_DDRABCD_CPU0_LVC1_SCL")
	)
	(segment
		(start 261.91972 -317.508382)
		(end 261.91972 -316.024006)
		(width 0.12954)
		(layer "B.Cu")
		(net "I3C_SPD_DDRABCD_CPU0_LVC1_SCL")
	)
	(segment
		(start 303.310036 -315.55563)
		(end 302.667924 -316.197742)
		(width 0.12954)
		(layer "B.Cu")
		(net "I3C_SPD_DDRABCD_CPU0_LVC1_SCL")
	)
	(segment
		(start 292.917372 -316.571376)
		(end 293.993824 -317.647828)
		(width 0.12954)
		(layer "B.Cu")
		(net "I3C_SPD_DDRABCD_CPU0_LVC1_SCL")
	)
	(segment
		(start 258.45262 -316.804548)
		(end 258.5466 -316.898528)
		(width 0.12954)
		(layer "B.Cu")
		(net "I3C_SPD_DDRABCD_CPU0_LVC1_SCL")
	)
	(segment
		(start 276.929342 -316.6872)
		(end 277.81885 -316.6872)
		(width 0.12954)
		(layer "B.Cu")
		(net "I3C_SPD_DDRABCD_CPU0_LVC1_SCL")
	)
	(segment
		(start 276.808184 -315.734446)
		(end 276.939756 -315.866018)
		(width 0.12954)
		(layer "B.Cu")
		(net "I3C_SPD_DDRABCD_CPU0_LVC1_SCL")
	)
	(segment
		(start 304.898044 -316.87643)
		(end 304.912776 -316.861444)
		(width 0.12954)
		(layer "B.Cu")
		(net "I3C_SPD_DDRABCD_CPU0_LVC1_SCL")
	)
	(segment
		(start 295.095422 -317.647828)
		(end 295.939972 -316.803278)
		(width 0.12954)
		(layer "B.Cu")
		(net "I3C_SPD_DDRABCD_CPU0_LVC1_SCL")
	)
	(segment
		(start 258.1402 -316.898528)
		(end 257.94716 -316.705488)
		(width 0.12954)
		(layer "B.Cu")
		(net "I3C_SPD_DDRABCD_CPU0_LVC1_SCL")
	)
	(segment
		(start 261.561834 -315.66612)
		(end 258.9022 -315.66612)
		(width 0.12954)
		(layer "B.Cu")
		(net "I3C_SPD_DDRABCD_CPU0_LVC1_SCL")
	)
	(segment
		(start 271.580864 -317.824358)
		(end 271.580864 -317.113412)
		(width 0.12954)
		(layer "B.Cu")
		(net "I3C_SPD_DDRABCD_CPU0_LVC1_SCL")
	)
	(segment
		(start 304.912776 -316.34557)
		(end 305.005486 -316.25286)
		(width 0.12954)
		(layer "B.Cu")
		(net "I3C_SPD_DDRABCD_CPU0_LVC1_SCL")
	)
	(segment
		(start 305.005486 -315.776864)
		(end 304.784252 -315.55563)
		(width 0.12954)
		(layer "B.Cu")
		(net "I3C_SPD_DDRABCD_CPU0_LVC1_SCL")
	)
	(segment
		(start 258.9022 -315.66612)
		(end 258.45262 -316.1157)
		(width 0.12954)
		(layer "B.Cu")
		(net "I3C_SPD_DDRABCD_CPU0_LVC1_SCL")
	)
	(segment
		(start 288.33191 -317.909448)
		(end 288.299144 -317.876682)
		(width 0.12954)
		(layer "B.Cu")
		(net "I3C_SPD_DDRABCD_CPU0_LVC1_SCL")
	)
	(segment
		(start 291.33546 -315.501528)
		(end 291.917628 -316.083696)
		(width 0.12954)
		(layer "B.Cu")
		(net "I3C_SPD_DDRABCD_CPU0_LVC1_SCL")
	)
	(segment
		(start 292.612318 -316.571376)
		(end 292.917372 -316.571376)
		(width 0.12954)
		(layer "B.Cu")
		(net "I3C_SPD_DDRABCD_CPU0_LVC1_SCL")
	)
	(segment
		(start 292.379908 -316.803786)
		(end 292.612318 -316.571376)
		(width 0.12954)
		(layer "B.Cu")
		(net "I3C_SPD_DDRABCD_CPU0_LVC1_SCL")
	)
	(segment
		(start 258.45262 -316.1157)
		(end 258.45262 -316.804548)
		(width 0.12954)
		(layer "B.Cu")
		(net "I3C_SPD_DDRABCD_CPU0_LVC1_SCL")
	)
	(segment
		(start 258.5466 -316.898528)
		(end 258.1402 -316.898528)
		(width 0.12954)
		(layer "B.Cu")
		(net "I3C_SPD_DDRABCD_CPU0_LVC1_SCL")
	)
	(segment
		(start 277.81885 -316.6872)
		(end 278.245824 -317.114174)
		(width 0.12954)
		(layer "B.Cu")
		(net "I3C_SPD_DDRABCD_CPU0_LVC1_SCL")
	)
	(segment
		(start 289.791648 -152.960578)
		(end 290.575238 -152.176988)
		(width 0.12954)
		(layer "B.Cu")
		(net "I3C_SPD_DDRABCD_CPU0_LVC1_SCL")
	)
	(segment
		(start 299.35932 -314.162948)
		(end 299.59808 -314.401708)
		(width 0.12954)
		(layer "B.Cu")
		(net "I3C_SPD_DDRABCD_CPU0_LVC1_SCL")
	)
	(segment
		(start 298.73702 -314.162948)
		(end 299.35932 -314.162948)
		(width 0.12954)
		(layer "B.Cu")
		(net "I3C_SPD_DDRABCD_CPU0_LVC1_SCL")
	)
	(segment
		(start 257.94716 -316.705488)
		(end 256.95148 -316.705488)
		(width 0.12954)
		(layer "B.Cu")
		(net "I3C_SPD_DDRABCD_CPU0_LVC1_SCL")
	)
	(segment
		(start 269.618714 -315.862208)
		(end 267.914882 -315.862208)
		(width 0.12954)
		(layer "B.Cu")
		(net "I3C_SPD_DDRABCD_CPU0_LVC1_SCL")
	)
	(segment
		(start 291.917628 -316.646052)
		(end 292.075362 -316.803786)
		(width 0.12954)
		(layer "B.Cu")
		(net "I3C_SPD_DDRABCD_CPU0_LVC1_SCL")
	)
	(segment
		(start 299.59808 -316.832742)
		(end 299.609002 -316.843664)
		(width 0.12954)
		(layer "B.Cu")
		(net "I3C_SPD_DDRABCD_CPU0_LVC1_SCL")
	)
	(segment
		(start 278.245824 -317.114174)
		(end 278.245824 -317.834772)
		(width 0.12954)
		(layer "B.Cu")
		(net "I3C_SPD_DDRABCD_CPU0_LVC1_SCL")
	)
	(segment
		(start 288.4805 -318.470788)
		(end 288.33191 -318.322198)
		(width 0.12954)
		(layer "B.Cu")
		(net "I3C_SPD_DDRABCD_CPU0_LVC1_SCL")
	)
	(segment
		(start 276.939756 -315.866018)
		(end 276.939756 -316.676786)
		(width 0.12954)
		(layer "B.Cu")
		(net "I3C_SPD_DDRABCD_CPU0_LVC1_SCL")
	)
	(segment
		(start 289.27552 -315.501528)
		(end 291.33546 -315.501528)
		(width 0.12954)
		(layer "B.Cu")
		(net "I3C_SPD_DDRABCD_CPU0_LVC1_SCL")
	)
	(segment
		(start 262.13562 -317.724282)
		(end 261.91972 -317.508382)
		(width 0.12954)
		(layer "B.Cu")
		(net "I3C_SPD_DDRABCD_CPU0_LVC1_SCL")
	)
	(segment
		(start 304.784252 -315.55563)
		(end 303.310036 -315.55563)
		(width 0.12954)
		(layer "B.Cu")
		(net "I3C_SPD_DDRABCD_CPU0_LVC1_SCL")
	)
	(segment
		(start 267.914882 -315.862208)
		(end 266.98448 -316.79261)
		(width 0.12954)
		(layer "B.Cu")
		(net "I3C_SPD_DDRABCD_CPU0_LVC1_SCL")
	)
	(segment
		(start 266.98448 -316.79261)
		(end 265.741658 -316.79261)
		(width 0.12954)
		(layer "B.Cu")
		(net "I3C_SPD_DDRABCD_CPU0_LVC1_SCL")
	)
	(segment
		(start 289.737038 -153.015188)
		(end 289.791648 -152.960578)
		(width 0.12954)
		(layer "B.Cu")
		(net "I3C_SPD_DDRABCD_CPU0_LVC1_SCL")
	)
	(segment
		(start 272.20164 -316.492636)
		(end 272.597626 -316.492636)
		(width 0.12954)
		(layer "B.Cu")
		(net "I3C_SPD_DDRABCD_CPU0_LVC1_SCL")
	)
	(segment
		(start 290.575238 -152.176988)
		(end 291.188648 -152.176988)
		(width 0.12954)
		(layer "B.Cu")
		(net "I3C_SPD_DDRABCD_CPU0_LVC1_SCL")
	)
	(segment
		(start 262.13562 -317.881762)
		(end 262.13562 -317.724282)
		(width 0.12954)
		(layer "B.Cu")
		(net "I3C_SPD_DDRABCD_CPU0_LVC1_SCL")
	)
	(segment
		(start 298.35856 -314.541408)
		(end 298.73702 -314.162948)
		(width 0.12954)
		(layer "B.Cu")
		(net "I3C_SPD_DDRABCD_CPU0_LVC1_SCL")
	)
	(segment
		(start 288.299144 -317.876682)
		(end 288.27603 -317.853568)
		(width 0.12954)
		(layer "B.Cu")
		(net "I3C_SPD_DDRABCD_CPU0_LVC1_SCL")
	)
	(segment
		(start 278.245824 -317.834772)
		(end 278.268938 -317.857886)
		(width 0.12954)
		(layer "B.Cu")
		(net "I3C_SPD_DDRABCD_CPU0_LVC1_SCL")
	)
	(segment
		(start 288.27603 -317.853568)
		(end 288.27603 -317.434722)
		(width 0.12954)
		(layer "B.Cu")
		(net "I3C_SPD_DDRABCD_CPU0_LVC1_SCL")
	)
	(segment
		(start 292.075362 -316.803786)
		(end 292.379908 -316.803786)
		(width 0.12954)
		(layer "B.Cu")
		(net "I3C_SPD_DDRABCD_CPU0_LVC1_SCL")
	)
	(segment
		(start 276.939756 -316.676786)
		(end 276.929342 -316.6872)
		(width 0.12954)
		(layer "B.Cu")
		(net "I3C_SPD_DDRABCD_CPU0_LVC1_SCL")
	)
	(segment
		(start 298.35856 -315.811408)
		(end 298.35856 -314.541408)
		(width 0.12954)
		(layer "B.Cu")
		(net "I3C_SPD_DDRABCD_CPU0_LVC1_SCL")
	)
	(segment
		(start 265.667236 -316.718188)
		(end 263.631426 -316.718188)
		(width 0.12954)
		(layer "B.Cu")
		(net "I3C_SPD_DDRABCD_CPU0_LVC1_SCL")
	)
	(segment
		(start 289.737038 -154.625548)
		(end 289.737038 -153.015188)
		(width 0.12954)
		(layer "B.Cu")
		(net "I3C_SPD_DDRABCD_CPU0_LVC1_SCL")
	)
	(segment
		(start 265.741658 -316.79261)
		(end 265.667236 -316.718188)
		(width 0.12954)
		(layer "B.Cu")
		(net "I3C_SPD_DDRABCD_CPU0_LVC1_SCL")
	)
	(segment
		(start 297.36669 -316.803278)
		(end 298.35856 -315.811408)
		(width 0.12954)
		(layer "B.Cu")
		(net "I3C_SPD_DDRABCD_CPU0_LVC1_SCL")
	)
	(segment
		(start 271.580864 -317.113412)
		(end 272.20164 -316.492636)
		(width 0.12954)
		(layer "B.Cu")
		(net "I3C_SPD_DDRABCD_CPU0_LVC1_SCL")
	)
	(segment
		(start 288.33191 -316.445138)
		(end 289.27552 -315.501528)
		(width 0.12954)
		(layer "B.Cu")
		(net "I3C_SPD_DDRABCD_CPU0_LVC1_SCL")
	)
	(segment
		(start 288.4805 -318.940688)
		(end 288.4805 -318.470788)
		(width 0.12954)
		(layer "B.Cu")
		(net "I3C_SPD_DDRABCD_CPU0_LVC1_SCL")
	)
	(segment
		(start 279.614122 -317.660528)
		(end 278.815038 -317.329566)
		(width 0.127)
		(layer "In2.Cu")
		(net "I3C_SPD_DDRABCD_CPU0_LVC1_SCL")
	)
	(segment
		(start 258.45262 -316.804548)
		(end 258.5466 -316.898528)
		(width 0.127)
		(layer "In2.Cu")
		(net "I3C_SPD_DDRABCD_CPU0_LVC1_SCL")
	)
	(segment
		(start 280.120344 -317.559944)
		(end 279.614122 -317.660528)
		(width 0.127)
		(layer "In2.Cu")
		(net "I3C_SPD_DDRABCD_CPU0_LVC1_SCL")
	)
	(segment
		(start 284.69209 -317.851028)
		(end 284.144212 -317.851028)
		(width 0.127)
		(layer "In2.Cu")
		(net "I3C_SPD_DDRABCD_CPU0_LVC1_SCL")
	)
	(segment
		(start 261.31774 -180.282088)
		(end 261.31774 -189.690248)
		(width 0.127)
		(layer "In2.Cu")
		(net "I3C_SPD_DDRABCD_CPU0_LVC1_SCL")
	)
	(segment
		(start 277.694898 -316.6872)
		(end 276.929342 -316.6872)
		(width 0.127)
		(layer "In2.Cu")
		(net "I3C_SPD_DDRABCD_CPU0_LVC1_SCL")
	)
	(segment
		(start 261.31774 -189.690248)
		(end 258.4831 -192.524888)
		(width 0.127)
		(layer "In2.Cu")
		(net "I3C_SPD_DDRABCD_CPU0_LVC1_SCL")
	)
	(segment
		(start 289.737038 -154.625548)
		(end 286.97428 -154.625548)
		(width 0.127)
		(layer "In2.Cu")
		(net "I3C_SPD_DDRABCD_CPU0_LVC1_SCL")
	)
	(segment
		(start 260.10362 -254.749808)
		(end 258.45262 -256.400808)
		(width 0.127)
		(layer "In2.Cu")
		(net "I3C_SPD_DDRABCD_CPU0_LVC1_SCL")
	)
	(segment
		(start 286.97428 -154.625548)
		(end 261.31774 -180.282088)
		(width 0.127)
		(layer "In2.Cu")
		(net "I3C_SPD_DDRABCD_CPU0_LVC1_SCL")
	)
	(segment
		(start 258.4831 -192.524888)
		(end 258.4831 -251.333508)
		(width 0.127)
		(layer "In2.Cu")
		(net "I3C_SPD_DDRABCD_CPU0_LVC1_SCL")
	)
	(segment
		(start 282.273756 -317.076328)
		(end 280.60396 -317.076328)
		(width 0.127)
		(layer "In2.Cu")
		(net "I3C_SPD_DDRABCD_CPU0_LVC1_SCL")
	)
	(segment
		(start 280.60396 -317.076328)
		(end 280.120344 -317.559944)
		(width 0.127)
		(layer "In2.Cu")
		(net "I3C_SPD_DDRABCD_CPU0_LVC1_SCL")
	)
	(segment
		(start 278.510492 -317.02502)
		(end 277.694898 -316.6872)
		(width 0.127)
		(layer "In2.Cu")
		(net "I3C_SPD_DDRABCD_CPU0_LVC1_SCL")
	)
	(segment
		(start 284.144212 -317.851028)
		(end 282.273756 -317.076328)
		(width 0.127)
		(layer "In2.Cu")
		(net "I3C_SPD_DDRABCD_CPU0_LVC1_SCL")
	)
	(segment
		(start 258.4831 -251.333508)
		(end 260.10362 -252.954028)
		(width 0.127)
		(layer "In2.Cu")
		(net "I3C_SPD_DDRABCD_CPU0_LVC1_SCL")
	)
	(segment
		(start 288.4805 -318.940688)
		(end 288.060892 -318.52108)
		(width 0.127)
		(layer "In2.Cu")
		(net "I3C_SPD_DDRABCD_CPU0_LVC1_SCL")
	)
	(segment
		(start 258.45262 -256.400808)
		(end 258.45262 -316.804548)
		(width 0.127)
		(layer "In2.Cu")
		(net "I3C_SPD_DDRABCD_CPU0_LVC1_SCL")
	)
	(segment
		(start 278.815038 -317.329566)
		(end 278.510492 -317.02502)
		(width 0.127)
		(layer "In2.Cu")
		(net "I3C_SPD_DDRABCD_CPU0_LVC1_SCL")
	)
	(segment
		(start 260.10362 -252.954028)
		(end 260.10362 -254.749808)
		(width 0.127)
		(layer "In2.Cu")
		(net "I3C_SPD_DDRABCD_CPU0_LVC1_SCL")
	)
	(segment
		(start 288.060892 -318.52108)
		(end 284.69209 -317.851028)
		(width 0.127)
		(layer "In2.Cu")
		(net "I3C_SPD_DDRABCD_CPU0_LVC1_SCL")
	)
	(via
		(at 294.143938 -154.699208)
		(size 0.6604)
		(drill 0.3302)
		(layers "F.Cu" "B.Cu")
		(net "I3C_SPD_DDRABCD_CPU0_LVC1_R_SDA")
	)
	(segment
		(start 291.987478 -153.946098)
		(end 292.998398 -153.946098)
		(width 0.12954)
		(layer "B.Cu")
		(net "I3C_SPD_DDRABCD_CPU0_LVC1_R_SDA")
	)
	(segment
		(start 294.413178 -154.429968)
		(end 294.143938 -154.699208)
		(width 0.12954)
		(layer "B.Cu")
		(net "I3C_SPD_DDRABCD_CPU0_LVC1_R_SDA")
	)
	(segment
		(start 295.873932 -153.626058)
		(end 294.897048 -153.626058)
		(width 0.12954)
		(layer "B.Cu")
		(net "I3C_SPD_DDRABCD_CPU0_LVC1_R_SDA")
	)
	(segment
		(start 294.897048 -153.626058)
		(end 294.413178 -154.109928)
		(width 0.12954)
		(layer "B.Cu")
		(net "I3C_SPD_DDRABCD_CPU0_LVC1_R_SDA")
	)
	(segment
		(start 291.986208 -153.944828)
		(end 291.987478 -153.946098)
		(width 0.12954)
		(layer "B.Cu")
		(net "I3C_SPD_DDRABCD_CPU0_LVC1_R_SDA")
	)
	(segment
		(start 293.390828 -153.946098)
		(end 292.998398 -153.946098)
		(width 0.12954)
		(layer "B.Cu")
		(net "I3C_SPD_DDRABCD_CPU0_LVC1_R_SDA")
	)
	(segment
		(start 294.413178 -154.109928)
		(end 294.413178 -154.429968)
		(width 0.12954)
		(layer "B.Cu")
		(net "I3C_SPD_DDRABCD_CPU0_LVC1_R_SDA")
	)
	(segment
		(start 294.143938 -154.699208)
		(end 293.390828 -153.946098)
		(width 0.12954)
		(layer "B.Cu")
		(net "I3C_SPD_DDRABCD_CPU0_LVC1_R_SDA")
	)
	(via
		(at 294.13962 -152.133808)
		(size 0.6604)
		(drill 0.3302)
		(layers "F.Cu" "B.Cu")
		(net "I3C_SPD_DDRABCD_CPU0_LVC1_R_SCL")
	)
	(segment
		(start 294.149018 -152.133808)
		(end 294.13962 -152.133808)
		(width 0.12954)
		(layer "B.Cu")
		(net "I3C_SPD_DDRABCD_CPU0_LVC1_R_SCL")
	)
	(segment
		(start 294.611298 -151.671528)
		(end 294.149018 -152.133808)
		(width 0.12954)
		(layer "B.Cu")
		(net "I3C_SPD_DDRABCD_CPU0_LVC1_R_SCL")
	)
	(segment
		(start 291.988748 -152.176988)
		(end 291.990018 -152.175718)
		(width 0.12954)
		(layer "B.Cu")
		(net "I3C_SPD_DDRABCD_CPU0_LVC1_R_SCL")
	)
	(segment
		(start 295.824402 -151.671528)
		(end 294.611298 -151.671528)
		(width 0.12954)
		(layer "B.Cu")
		(net "I3C_SPD_DDRABCD_CPU0_LVC1_R_SCL")
	)
	(segment
		(start 295.873932 -151.721058)
		(end 295.824402 -151.671528)
		(width 0.12954)
		(layer "B.Cu")
		(net "I3C_SPD_DDRABCD_CPU0_LVC1_R_SCL")
	)
	(segment
		(start 294.13962 -152.133808)
		(end 293.025068 -152.133808)
		(width 0.12954)
		(layer "B.Cu")
		(net "I3C_SPD_DDRABCD_CPU0_LVC1_R_SCL")
	)
	(segment
		(start 291.990018 -152.175718)
		(end 292.983158 -152.175718)
		(width 0.12954)
		(layer "B.Cu")
		(net "I3C_SPD_DDRABCD_CPU0_LVC1_R_SCL")
	)
	(segment
		(start 293.025068 -152.133808)
		(end 292.983158 -152.175718)
		(width 0.12954)
		(layer "B.Cu")
		(net "I3C_SPD_DDRABCD_CPU0_LVC1_R_SCL")
	)
	(via
		(at 189.350396 -14.714728)
		(size 0.508)
		(drill 0.254)
		(layers "F.Cu" "B.Cu")
		(net "I3C_SPD_DDRABCD_CPU0_BMC_SDA")
	)
	(via
		(at 297.36796 -152.941528)
		(size 0.762)
		(drill 0.254)
		(layers "F.Cu" "B.Cu")
		(net "I3C_SPD_DDRABCD_CPU0_BMC_SDA")
	)
	(segment
		(start 189.350396 -14.00048)
		(end 189.350396 -14.714728)
		(width 0.12954)
		(layer "B.Cu")
		(net "I3C_SPD_DDRABCD_CPU0_BMC_SDA")
	)
	(segment
		(start 297.31843 -152.991058)
		(end 295.873932 -152.991058)
		(width 0.12954)
		(layer "B.Cu")
		(net "I3C_SPD_DDRABCD_CPU0_BMC_SDA")
	)
	(segment
		(start 297.36796 -152.941528)
		(end 297.31843 -152.991058)
		(width 0.12954)
		(layer "B.Cu")
		(net "I3C_SPD_DDRABCD_CPU0_BMC_SDA")
	)
	(segment
		(start 299.2374 -150.510748)
		(end 299.2374 -151.729948)
		(width 0.127)
		(layer "In2.Cu")
		(net "I3C_SPD_DDRABCD_CPU0_BMC_SDA")
	)
	(segment
		(start 279.240996 -142.888208)
		(end 290.462716 -142.888208)
		(width 0.127)
		(layer "In2.Cu")
		(net "I3C_SPD_DDRABCD_CPU0_BMC_SDA")
	)
	(segment
		(start 194.917568 -26.116534)
		(end 194.917568 -29.091636)
		(width 0.127)
		(layer "In2.Cu")
		(net "I3C_SPD_DDRABCD_CPU0_BMC_SDA")
	)
	(segment
		(start 271.55648 -94.208092)
		(end 271.55648 -135.203692)
		(width 0.127)
		(layer "In2.Cu")
		(net "I3C_SPD_DDRABCD_CPU0_BMC_SDA")
	)
	(segment
		(start 290.462716 -142.888208)
		(end 297.554396 -149.979888)
		(width 0.127)
		(layer "In2.Cu")
		(net "I3C_SPD_DDRABCD_CPU0_BMC_SDA")
	)
	(segment
		(start 298.12107 -152.188418)
		(end 297.36796 -152.941528)
		(width 0.127)
		(layer "In2.Cu")
		(net "I3C_SPD_DDRABCD_CPU0_BMC_SDA")
	)
	(segment
		(start 263.679432 -86.331044)
		(end 271.55648 -94.208092)
		(width 0.127)
		(layer "In2.Cu")
		(net "I3C_SPD_DDRABCD_CPU0_BMC_SDA")
	)
	(segment
		(start 196.002148 -18.939256)
		(end 196.002148 -25.031954)
		(width 0.127)
		(layer "In2.Cu")
		(net "I3C_SPD_DDRABCD_CPU0_BMC_SDA")
	)
	(segment
		(start 189.350396 -14.714728)
		(end 189.350396 -14.941804)
		(width 0.127)
		(layer "In2.Cu")
		(net "I3C_SPD_DDRABCD_CPU0_BMC_SDA")
	)
	(segment
		(start 189.350396 -14.941804)
		(end 191.54394 -17.135348)
		(width 0.127)
		(layer "In2.Cu")
		(net "I3C_SPD_DDRABCD_CPU0_BMC_SDA")
	)
	(segment
		(start 191.54394 -17.135348)
		(end 194.19824 -17.135348)
		(width 0.127)
		(layer "In2.Cu")
		(net "I3C_SPD_DDRABCD_CPU0_BMC_SDA")
	)
	(segment
		(start 194.19824 -17.135348)
		(end 196.002148 -18.939256)
		(width 0.127)
		(layer "In2.Cu")
		(net "I3C_SPD_DDRABCD_CPU0_BMC_SDA")
	)
	(segment
		(start 194.917568 -29.091636)
		(end 214.81288 -48.986948)
		(width 0.127)
		(layer "In2.Cu")
		(net "I3C_SPD_DDRABCD_CPU0_BMC_SDA")
	)
	(segment
		(start 298.77893 -152.188418)
		(end 298.12107 -152.188418)
		(width 0.127)
		(layer "In2.Cu")
		(net "I3C_SPD_DDRABCD_CPU0_BMC_SDA")
	)
	(segment
		(start 253.956312 -86.331044)
		(end 263.679432 -86.331044)
		(width 0.127)
		(layer "In2.Cu")
		(net "I3C_SPD_DDRABCD_CPU0_BMC_SDA")
	)
	(segment
		(start 196.002148 -25.031954)
		(end 194.917568 -26.116534)
		(width 0.127)
		(layer "In2.Cu")
		(net "I3C_SPD_DDRABCD_CPU0_BMC_SDA")
	)
	(segment
		(start 297.554396 -149.979888)
		(end 298.70654 -149.979888)
		(width 0.127)
		(layer "In2.Cu")
		(net "I3C_SPD_DDRABCD_CPU0_BMC_SDA")
	)
	(segment
		(start 216.612216 -48.986948)
		(end 253.956312 -86.331044)
		(width 0.127)
		(layer "In2.Cu")
		(net "I3C_SPD_DDRABCD_CPU0_BMC_SDA")
	)
	(segment
		(start 271.55648 -135.203692)
		(end 279.240996 -142.888208)
		(width 0.127)
		(layer "In2.Cu")
		(net "I3C_SPD_DDRABCD_CPU0_BMC_SDA")
	)
	(segment
		(start 298.70654 -149.979888)
		(end 299.2374 -150.510748)
		(width 0.127)
		(layer "In2.Cu")
		(net "I3C_SPD_DDRABCD_CPU0_BMC_SDA")
	)
	(segment
		(start 214.81288 -48.986948)
		(end 216.612216 -48.986948)
		(width 0.127)
		(layer "In2.Cu")
		(net "I3C_SPD_DDRABCD_CPU0_BMC_SDA")
	)
	(segment
		(start 299.2374 -151.729948)
		(end 298.77893 -152.188418)
		(width 0.127)
		(layer "In2.Cu")
		(net "I3C_SPD_DDRABCD_CPU0_BMC_SDA")
	)
	(via
		(at 299.10278 -152.921208)
		(size 0.762)
		(drill 0.254)
		(layers "F.Cu" "B.Cu")
		(net "I3C_SPD_DDRABCD_CPU0_BMC_SCL")
	)
	(via
		(at 190.367158 -14.714728)
		(size 0.508)
		(drill 0.254)
		(layers "F.Cu" "B.Cu")
		(net "I3C_SPD_DDRABCD_CPU0_BMC_SCL")
	)
	(segment
		(start 299.10278 -152.30475)
		(end 298.802298 -152.004268)
		(width 0.12954)
		(layer "B.Cu")
		(net "I3C_SPD_DDRABCD_CPU0_BMC_SCL")
	)
	(segment
		(start 298.249086 -152.004268)
		(end 297.330876 -151.086058)
		(width 0.12954)
		(layer "B.Cu")
		(net "I3C_SPD_DDRABCD_CPU0_BMC_SCL")
	)
	(segment
		(start 299.10278 -152.921208)
		(end 299.10278 -152.30475)
		(width 0.12954)
		(layer "B.Cu")
		(net "I3C_SPD_DDRABCD_CPU0_BMC_SCL")
	)
	(segment
		(start 298.802298 -152.004268)
		(end 298.249086 -152.004268)
		(width 0.12954)
		(layer "B.Cu")
		(net "I3C_SPD_DDRABCD_CPU0_BMC_SCL")
	)
	(segment
		(start 190.367158 -14.00048)
		(end 190.367158 -14.714728)
		(width 0.12954)
		(layer "B.Cu")
		(net "I3C_SPD_DDRABCD_CPU0_BMC_SCL")
	)
	(segment
		(start 297.330876 -151.086058)
		(end 295.873932 -151.086058)
		(width 0.12954)
		(layer "B.Cu")
		(net "I3C_SPD_DDRABCD_CPU0_BMC_SCL")
	)
	(segment
		(start 197.137528 -19.152108)
		(end 197.137528 -29.273754)
		(width 0.127)
		(layer "In2.Cu")
		(net "I3C_SPD_DDRABCD_CPU0_BMC_SCL")
	)
	(segment
		(start 197.137528 -29.273754)
		(end 196.742304 -29.668978)
		(width 0.127)
		(layer "In2.Cu")
		(net "I3C_SPD_DDRABCD_CPU0_BMC_SCL")
	)
	(segment
		(start 290.72586 -142.253208)
		(end 297.73372 -149.261068)
		(width 0.127)
		(layer "In2.Cu")
		(net "I3C_SPD_DDRABCD_CPU0_BMC_SCL")
	)
	(segment
		(start 263.87044 -85.623908)
		(end 272.19148 -93.944948)
		(width 0.127)
		(layer "In2.Cu")
		(net "I3C_SPD_DDRABCD_CPU0_BMC_SCL")
	)
	(segment
		(start 297.73372 -149.261068)
		(end 298.885864 -149.261068)
		(width 0.127)
		(layer "In2.Cu")
		(net "I3C_SPD_DDRABCD_CPU0_BMC_SCL")
	)
	(segment
		(start 196.742304 -29.99994)
		(end 213.682072 -46.939708)
		(width 0.127)
		(layer "In2.Cu")
		(net "I3C_SPD_DDRABCD_CPU0_BMC_SCL")
	)
	(segment
		(start 190.367158 -14.714728)
		(end 190.367158 -14.9479)
		(width 0.127)
		(layer "In2.Cu")
		(net "I3C_SPD_DDRABCD_CPU0_BMC_SCL")
	)
	(segment
		(start 272.19148 -134.940548)
		(end 279.50414 -142.253208)
		(width 0.127)
		(layer "In2.Cu")
		(net "I3C_SPD_DDRABCD_CPU0_BMC_SCL")
	)
	(segment
		(start 194.460114 -16.474694)
		(end 197.137528 -19.152108)
		(width 0.127)
		(layer "In2.Cu")
		(net "I3C_SPD_DDRABCD_CPU0_BMC_SCL")
	)
	(segment
		(start 191.893952 -16.474694)
		(end 194.460114 -16.474694)
		(width 0.127)
		(layer "In2.Cu")
		(net "I3C_SPD_DDRABCD_CPU0_BMC_SCL")
	)
	(segment
		(start 215.46312 -46.939708)
		(end 254.14732 -85.623908)
		(width 0.127)
		(layer "In2.Cu")
		(net "I3C_SPD_DDRABCD_CPU0_BMC_SCL")
	)
	(segment
		(start 190.367158 -14.9479)
		(end 191.893952 -16.474694)
		(width 0.127)
		(layer "In2.Cu")
		(net "I3C_SPD_DDRABCD_CPU0_BMC_SCL")
	)
	(segment
		(start 298.885864 -149.261068)
		(end 299.9994 -150.374604)
		(width 0.127)
		(layer "In2.Cu")
		(net "I3C_SPD_DDRABCD_CPU0_BMC_SCL")
	)
	(segment
		(start 299.9994 -150.374604)
		(end 299.9994 -152.024588)
		(width 0.127)
		(layer "In2.Cu")
		(net "I3C_SPD_DDRABCD_CPU0_BMC_SCL")
	)
	(segment
		(start 279.50414 -142.253208)
		(end 290.72586 -142.253208)
		(width 0.127)
		(layer "In2.Cu")
		(net "I3C_SPD_DDRABCD_CPU0_BMC_SCL")
	)
	(segment
		(start 196.742304 -29.668978)
		(end 196.742304 -29.99994)
		(width 0.127)
		(layer "In2.Cu")
		(net "I3C_SPD_DDRABCD_CPU0_BMC_SCL")
	)
	(segment
		(start 254.14732 -85.623908)
		(end 263.87044 -85.623908)
		(width 0.127)
		(layer "In2.Cu")
		(net "I3C_SPD_DDRABCD_CPU0_BMC_SCL")
	)
	(segment
		(start 272.19148 -93.944948)
		(end 272.19148 -134.940548)
		(width 0.127)
		(layer "In2.Cu")
		(net "I3C_SPD_DDRABCD_CPU0_BMC_SCL")
	)
	(segment
		(start 213.682072 -46.939708)
		(end 215.46312 -46.939708)
		(width 0.127)
		(layer "In2.Cu")
		(net "I3C_SPD_DDRABCD_CPU0_BMC_SCL")
	)
	(segment
		(start 299.9994 -152.024588)
		(end 299.10278 -152.921208)
		(width 0.127)
		(layer "In2.Cu")
		(net "I3C_SPD_DDRABCD_CPU0_BMC_SCL")
	)
	(segment
		(start 188.062108 -12.683998)
		(end 188.061854 -12.683744)
		(width 0.12954)
		(layer "F.Cu")
		(net "I3C_SPD_DDRABCD_CPU0_BMC_R_SDA")
	)
	(segment
		(start 188.062108 -13.600176)
		(end 188.062108 -12.683998)
		(width 0.12954)
		(layer "F.Cu")
		(net "I3C_SPD_DDRABCD_CPU0_BMC_R_SDA")
	)
	(segment
		(start 188.061854 -11.907774)
		(end 189.4586 -10.511028)
		(width 0.12954)
		(layer "F.Cu")
		(net "I3C_SPD_DDRABCD_CPU0_BMC_R_SDA")
	)
	(segment
		(start 189.4586 -10.511028)
		(end 189.4586 -10.251948)
		(width 0.12954)
		(layer "F.Cu")
		(net "I3C_SPD_DDRABCD_CPU0_BMC_R_SDA")
	)
	(segment
		(start 188.061854 -12.683744)
		(end 188.061854 -11.907774)
		(width 0.12954)
		(layer "F.Cu")
		(net "I3C_SPD_DDRABCD_CPU0_BMC_R_SDA")
	)
	(via
		(at 189.4586 -10.251948)
		(size 0.508)
		(drill 0.254)
		(layers "F.Cu" "B.Cu")
		(net "I3C_SPD_DDRABCD_CPU0_BMC_R_SDA")
	)
	(segment
		(start 188.75248 -10.958068)
		(end 188.75248 -12.593066)
		(width 0.12954)
		(layer "B.Cu")
		(net "I3C_SPD_DDRABCD_CPU0_BMC_R_SDA")
	)
	(segment
		(start 189.211712 -13.20038)
		(end 189.350396 -13.20038)
		(width 0.12954)
		(layer "B.Cu")
		(net "I3C_SPD_DDRABCD_CPU0_BMC_R_SDA")
	)
	(segment
		(start 188.857128 -12.845796)
		(end 189.211712 -13.20038)
		(width 0.12954)
		(layer "B.Cu")
		(net "I3C_SPD_DDRABCD_CPU0_BMC_R_SDA")
	)
	(segment
		(start 188.75248 -12.593066)
		(end 188.857128 -12.845796)
		(width 0.12954)
		(layer "B.Cu")
		(net "I3C_SPD_DDRABCD_CPU0_BMC_R_SDA")
	)
	(segment
		(start 189.4586 -10.251948)
		(end 188.75248 -10.958068)
		(width 0.12954)
		(layer "B.Cu")
		(net "I3C_SPD_DDRABCD_CPU0_BMC_R_SDA")
	)
	(segment
		(start 188.662056 -12.683998)
		(end 188.661802 -12.683744)
		(width 0.12954)
		(layer "F.Cu")
		(net "I3C_SPD_DDRABCD_CPU0_BMC_R_SCL")
	)
	(segment
		(start 188.661802 -12.683744)
		(end 188.661802 -12.146026)
		(width 0.12954)
		(layer "F.Cu")
		(net "I3C_SPD_DDRABCD_CPU0_BMC_R_SCL")
	)
	(segment
		(start 189.05728 -11.750548)
		(end 189.5094 -11.750548)
		(width 0.12954)
		(layer "F.Cu")
		(net "I3C_SPD_DDRABCD_CPU0_BMC_R_SCL")
	)
	(segment
		(start 188.661802 -12.146026)
		(end 189.05728 -11.750548)
		(width 0.12954)
		(layer "F.Cu")
		(net "I3C_SPD_DDRABCD_CPU0_BMC_R_SCL")
	)
	(segment
		(start 188.662056 -13.600176)
		(end 188.662056 -12.683998)
		(width 0.12954)
		(layer "F.Cu")
		(net "I3C_SPD_DDRABCD_CPU0_BMC_R_SCL")
	)
	(via
		(at 189.5094 -11.750548)
		(size 0.508)
		(drill 0.254)
		(layers "F.Cu" "B.Cu")
		(net "I3C_SPD_DDRABCD_CPU0_BMC_R_SCL")
	)
	(segment
		(start 190.0174 -11.750548)
		(end 190.367158 -12.100306)
		(width 0.12954)
		(layer "B.Cu")
		(net "I3C_SPD_DDRABCD_CPU0_BMC_R_SCL")
	)
	(segment
		(start 189.5094 -11.750548)
		(end 190.0174 -11.750548)
		(width 0.12954)
		(layer "B.Cu")
		(net "I3C_SPD_DDRABCD_CPU0_BMC_R_SCL")
	)
	(segment
		(start 190.367158 -12.100306)
		(end 190.367158 -13.20038)
		(width 0.12954)
		(layer "B.Cu")
		(net "I3C_SPD_DDRABCD_CPU0_BMC_R_SCL")
	)
	(segment
		(start 327.028302 -57.88533)
		(end 327.028302 -58.198004)
		(width 0.0889)
		(layer "F.Cu")
		(net "H_THERMTRIP_LVC1_N")
	)
	(segment
		(start 326.803512 -58.655458)
		(end 326.384666 -59.074304)
		(width 0.0889)
		(layer "F.Cu")
		(net "H_THERMTRIP_LVC1_N")
	)
	(segment
		(start 327.41489 -56.95442)
		(end 327.41489 -57.498742)
		(width 0.0889)
		(layer "F.Cu")
		(net "H_THERMTRIP_LVC1_N")
	)
	(segment
		(start 320.92519 -63.896748)
		(end 320.641472 -63.896748)
		(width 0.12954)
		(layer "F.Cu")
		(net "H_THERMTRIP_LVC1_N")
	)
	(segment
		(start 321.32651 -63.495428)
		(end 320.92519 -63.896748)
		(width 0.12954)
		(layer "F.Cu")
		(net "H_THERMTRIP_LVC1_N")
	)
	(segment
		(start 320.321178 -64.572388)
		(end 318.414654 -64.572388)
		(width 0.12954)
		(layer "F.Cu")
		(net "H_THERMTRIP_LVC1_N")
	)
	(segment
		(start 317.83528 -62.359286)
		(end 317.818262 -62.342268)
		(width 0.12954)
		(layer "F.Cu")
		(net "H_THERMTRIP_LVC1_N")
	)
	(segment
		(start 326.384666 -59.074304)
		(end 325.747634 -59.074304)
		(width 0.12954)
		(layer "F.Cu")
		(net "H_THERMTRIP_LVC1_N")
	)
	(segment
		(start 327.41489 -57.498742)
		(end 327.028302 -57.88533)
		(width 0.0889)
		(layer "F.Cu")
		(net "H_THERMTRIP_LVC1_N")
	)
	(segment
		(start 318.414654 -64.572388)
		(end 317.83528 -63.993014)
		(width 0.12954)
		(layer "F.Cu")
		(net "H_THERMTRIP_LVC1_N")
	)
	(segment
		(start 327.028302 -58.198004)
		(end 326.803512 -58.422794)
		(width 0.0889)
		(layer "F.Cu")
		(net "H_THERMTRIP_LVC1_N")
	)
	(segment
		(start 317.83528 -63.993014)
		(end 317.83528 -62.359286)
		(width 0.12954)
		(layer "F.Cu")
		(net "H_THERMTRIP_LVC1_N")
	)
	(segment
		(start 320.641472 -63.896748)
		(end 320.641472 -64.252094)
		(width 0.12954)
		(layer "F.Cu")
		(net "H_THERMTRIP_LVC1_N")
	)
	(segment
		(start 325.747634 -59.074304)
		(end 321.32651 -63.495428)
		(width 0.12954)
		(layer "F.Cu")
		(net "H_THERMTRIP_LVC1_N")
	)
	(segment
		(start 320.641472 -64.252094)
		(end 320.321178 -64.572388)
		(width 0.12954)
		(layer "F.Cu")
		(net "H_THERMTRIP_LVC1_N")
	)
	(segment
		(start 326.803512 -58.422794)
		(end 326.803512 -58.655458)
		(width 0.0889)
		(layer "F.Cu")
		(net "H_THERMTRIP_LVC1_N")
	)
	(via
		(at 321.32651 -63.495428)
		(size 0.508)
		(drill 0.254)
		(layers "F.Cu" "B.Cu")
		(net "H_THERMTRIP_LVC1_N")
	)
	(segment
		(start 105.061766 -233.06405)
		(end 105.061766 -232.528364)
		(width 0.12954)
		(layer "F.Cu")
		(net "H_PMAX_TRIGGER_IO_CPU1")
	)
	(segment
		(start 105.061512 -233.064304)
		(end 105.061766 -233.06405)
		(width 0.12954)
		(layer "F.Cu")
		(net "H_PMAX_TRIGGER_IO_CPU1")
	)
	(via
		(at 105.061766 -232.528364)
		(size 0.4572)
		(drill 0.2032)
		(layers "F.Cu" "B.Cu")
		(net "H_PMAX_TRIGGER_IO_CPU1")
	)
	(via
		(at 71.733918 -223.63811)
		(size 0.6604)
		(drill 0.3302)
		(layers "F.Cu" "B.Cu")
		(net "H_PMAX_TRIGGER_IO_CPU1")
	)
	(segment
		(start 96.886014 -231.39019)
		(end 96.871282 -231.398826)
		(width 0.0889)
		(layer "B.Cu")
		(net "H_PMAX_TRIGGER_IO_CPU1")
	)
	(segment
		(start 99.705414 -231.39019)
		(end 99.690682 -231.398826)
		(width 0.0889)
		(layer "B.Cu")
		(net "H_PMAX_TRIGGER_IO_CPU1")
	)
	(segment
		(start 88.427814 -231.39019)
		(end 88.4174 -231.396286)
		(width 0.0889)
		(layer "B.Cu")
		(net "H_PMAX_TRIGGER_IO_CPU1")
	)
	(segment
		(start 89.367614 -231.39019)
		(end 89.352882 -231.398826)
		(width 0.0889)
		(layer "B.Cu")
		(net "H_PMAX_TRIGGER_IO_CPU1")
	)
	(segment
		(start 101.585014 -231.39019)
		(end 101.5746 -231.396286)
		(width 0.0889)
		(layer "B.Cu")
		(net "H_PMAX_TRIGGER_IO_CPU1")
	)
	(segment
		(start 101.9683 -231.39527)
		(end 101.95941 -231.39019)
		(width 0.0889)
		(layer "B.Cu")
		(net "H_PMAX_TRIGGER_IO_CPU1")
	)
	(segment
		(start 104.323896 -232.212642)
		(end 104.309164 -232.204006)
		(width 0.0889)
		(layer "B.Cu")
		(net "H_PMAX_TRIGGER_IO_CPU1")
	)
	(segment
		(start 90.307414 -231.39019)
		(end 90.292682 -231.398826)
		(width 0.0889)
		(layer "B.Cu")
		(net "H_PMAX_TRIGGER_IO_CPU1")
	)
	(segment
		(start 78.670658 -232.03789)
		(end 71.733918 -225.10115)
		(width 0.12954)
		(layer "B.Cu")
		(net "H_PMAX_TRIGGER_IO_CPU1")
	)
	(segment
		(start 87.675466 -231.33939)
		(end 84.56295 -231.33939)
		(width 0.0889)
		(layer "B.Cu")
		(net "H_PMAX_TRIGGER_IO_CPU1")
	)
	(segment
		(start 102.429564 -232.204006)
		(end 102.423468 -232.20045)
		(width 0.0889)
		(layer "B.Cu")
		(net "H_PMAX_TRIGGER_IO_CPU1")
	)
	(segment
		(start 95.946214 -231.39019)
		(end 95.931482 -231.398826)
		(width 0.0889)
		(layer "B.Cu")
		(net "H_PMAX_TRIGGER_IO_CPU1")
	)
	(segment
		(start 71.733918 -221.9452)
		(end 70.012306 -220.223588)
		(width 0.12954)
		(layer "B.Cu")
		(net "H_PMAX_TRIGGER_IO_CPU1")
	)
	(segment
		(start 103.384096 -232.212642)
		(end 103.369364 -232.204006)
		(width 0.0889)
		(layer "B.Cu")
		(net "H_PMAX_TRIGGER_IO_CPU1")
	)
	(segment
		(start 92.187014 -231.39019)
		(end 92.172282 -231.398826)
		(width 0.0889)
		(layer "B.Cu")
		(net "H_PMAX_TRIGGER_IO_CPU1")
	)
	(segment
		(start 104.905302 -232.257346)
		(end 104.816148 -232.23347)
		(width 0.0889)
		(layer "B.Cu")
		(net "H_PMAX_TRIGGER_IO_CPU1")
	)
	(segment
		(start 98.765614 -231.39019)
		(end 98.750882 -231.398826)
		(width 0.0889)
		(layer "B.Cu")
		(net "H_PMAX_TRIGGER_IO_CPU1")
	)
	(segment
		(start 95.006414 -231.39019)
		(end 94.996 -231.396286)
		(width 0.0889)
		(layer "B.Cu")
		(net "H_PMAX_TRIGGER_IO_CPU1")
	)
	(segment
		(start 100.645468 -231.39019)
		(end 100.635054 -231.396286)
		(width 0.0889)
		(layer "B.Cu")
		(net "H_PMAX_TRIGGER_IO_CPU1")
	)
	(segment
		(start 105.061766 -232.528364)
		(end 104.905302 -232.257346)
		(width 0.0889)
		(layer "B.Cu")
		(net "H_PMAX_TRIGGER_IO_CPU1")
	)
	(segment
		(start 84.56295 -231.33939)
		(end 83.86445 -232.03789)
		(width 0.0889)
		(layer "B.Cu")
		(net "H_PMAX_TRIGGER_IO_CPU1")
	)
	(segment
		(start 71.733918 -225.10115)
		(end 71.733918 -223.63811)
		(width 0.12954)
		(layer "B.Cu")
		(net "H_PMAX_TRIGGER_IO_CPU1")
	)
	(segment
		(start 102.444296 -232.212642)
		(end 102.429564 -232.204006)
		(width 0.0889)
		(layer "B.Cu")
		(net "H_PMAX_TRIGGER_IO_CPU1")
	)
	(segment
		(start 94.066868 -231.39019)
		(end 94.056454 -231.396286)
		(width 0.0889)
		(layer "B.Cu")
		(net "H_PMAX_TRIGGER_IO_CPU1")
	)
	(segment
		(start 93.126814 -231.39019)
		(end 93.112082 -231.398826)
		(width 0.0889)
		(layer "B.Cu")
		(net "H_PMAX_TRIGGER_IO_CPU1")
	)
	(segment
		(start 83.86445 -232.03789)
		(end 78.670658 -232.03789)
		(width 0.12954)
		(layer "B.Cu")
		(net "H_PMAX_TRIGGER_IO_CPU1")
	)
	(segment
		(start 71.733918 -223.63811)
		(end 71.733918 -221.9452)
		(width 0.12954)
		(layer "B.Cu")
		(net "H_PMAX_TRIGGER_IO_CPU1")
	)
	(arc
		(start 101.5746 -231.396286)
		(mid 101.296422 -231.465978)
		(end 101.019864 -231.39019)
		(width 0.0889)
		(layer "B.Cu")
		(net "H_PMAX_TRIGGER_IO_CPU1")
	)
	(arc
		(start 101.019864 -231.39019)
		(mid 100.832666 -231.340047)
		(end 100.645468 -231.39019)
		(width 0.0889)
		(layer "B.Cu")
		(net "H_PMAX_TRIGGER_IO_CPU1")
	)
	(arc
		(start 102.423468 -232.20045)
		(mid 102.220881 -231.994099)
		(end 102.146862 -231.714548)
		(width 0.0889)
		(layer "B.Cu")
		(net "H_PMAX_TRIGGER_IO_CPU1")
	)
	(arc
		(start 97.825814 -231.39019)
		(mid 97.543112 -231.465932)
		(end 97.26041 -231.39019)
		(width 0.0889)
		(layer "B.Cu")
		(net "H_PMAX_TRIGGER_IO_CPU1")
	)
	(arc
		(start 95.38081 -231.39019)
		(mid 95.193612 -231.340047)
		(end 95.006414 -231.39019)
		(width 0.0889)
		(layer "B.Cu")
		(net "H_PMAX_TRIGGER_IO_CPU1")
	)
	(arc
		(start 103.369364 -232.204006)
		(mid 103.182166 -232.153863)
		(end 102.994968 -232.204006)
		(width 0.0889)
		(layer "B.Cu")
		(net "H_PMAX_TRIGGER_IO_CPU1")
	)
	(arc
		(start 87.862664 -231.39019)
		(mid 87.772408 -231.352468)
		(end 87.675466 -231.33939)
		(width 0.0889)
		(layer "B.Cu")
		(net "H_PMAX_TRIGGER_IO_CPU1")
	)
	(arc
		(start 100.07981 -231.39019)
		(mid 99.892612 -231.340047)
		(end 99.705414 -231.39019)
		(width 0.0889)
		(layer "B.Cu")
		(net "H_PMAX_TRIGGER_IO_CPU1")
	)
	(arc
		(start 99.690682 -231.398826)
		(mid 99.414241 -231.465992)
		(end 99.14001 -231.39019)
		(width 0.0889)
		(layer "B.Cu")
		(net "H_PMAX_TRIGGER_IO_CPU1")
	)
	(arc
		(start 102.146862 -231.714548)
		(mid 102.099183 -231.531648)
		(end 101.9683 -231.39527)
		(width 0.0889)
		(layer "B.Cu")
		(net "H_PMAX_TRIGGER_IO_CPU1")
	)
	(arc
		(start 96.32061 -231.39019)
		(mid 96.133412 -231.340047)
		(end 95.946214 -231.39019)
		(width 0.0889)
		(layer "B.Cu")
		(net "H_PMAX_TRIGGER_IO_CPU1")
	)
	(arc
		(start 104.816148 -232.23347)
		(mid 104.567643 -232.279457)
		(end 104.323896 -232.212642)
		(width 0.0889)
		(layer "B.Cu")
		(net "H_PMAX_TRIGGER_IO_CPU1")
	)
	(arc
		(start 102.994968 -232.204006)
		(mid 102.720769 -232.279841)
		(end 102.444296 -232.212642)
		(width 0.0889)
		(layer "B.Cu")
		(net "H_PMAX_TRIGGER_IO_CPU1")
	)
	(arc
		(start 103.934768 -232.204006)
		(mid 103.660569 -232.279841)
		(end 103.384096 -232.212642)
		(width 0.0889)
		(layer "B.Cu")
		(net "H_PMAX_TRIGGER_IO_CPU1")
	)
	(arc
		(start 100.635054 -231.396286)
		(mid 100.356622 -231.4661)
		(end 100.07981 -231.39019)
		(width 0.0889)
		(layer "B.Cu")
		(net "H_PMAX_TRIGGER_IO_CPU1")
	)
	(arc
		(start 91.62161 -231.39019)
		(mid 91.434412 -231.340047)
		(end 91.247214 -231.39019)
		(width 0.0889)
		(layer "B.Cu")
		(net "H_PMAX_TRIGGER_IO_CPU1")
	)
	(arc
		(start 91.247214 -231.39019)
		(mid 90.964512 -231.465932)
		(end 90.68181 -231.39019)
		(width 0.0889)
		(layer "B.Cu")
		(net "H_PMAX_TRIGGER_IO_CPU1")
	)
	(arc
		(start 94.056454 -231.396286)
		(mid 93.778022 -231.4661)
		(end 93.50121 -231.39019)
		(width 0.0889)
		(layer "B.Cu")
		(net "H_PMAX_TRIGGER_IO_CPU1")
	)
	(arc
		(start 101.95941 -231.39019)
		(mid 101.772212 -231.340047)
		(end 101.585014 -231.39019)
		(width 0.0889)
		(layer "B.Cu")
		(net "H_PMAX_TRIGGER_IO_CPU1")
	)
	(arc
		(start 89.74201 -231.39019)
		(mid 89.554812 -231.340047)
		(end 89.367614 -231.39019)
		(width 0.0889)
		(layer "B.Cu")
		(net "H_PMAX_TRIGGER_IO_CPU1")
	)
	(arc
		(start 93.50121 -231.39019)
		(mid 93.314012 -231.340047)
		(end 93.126814 -231.39019)
		(width 0.0889)
		(layer "B.Cu")
		(net "H_PMAX_TRIGGER_IO_CPU1")
	)
	(arc
		(start 88.80221 -231.39019)
		(mid 88.615012 -231.340047)
		(end 88.427814 -231.39019)
		(width 0.0889)
		(layer "B.Cu")
		(net "H_PMAX_TRIGGER_IO_CPU1")
	)
	(arc
		(start 99.14001 -231.39019)
		(mid 98.952812 -231.340047)
		(end 98.765614 -231.39019)
		(width 0.0889)
		(layer "B.Cu")
		(net "H_PMAX_TRIGGER_IO_CPU1")
	)
	(arc
		(start 89.352882 -231.398826)
		(mid 89.076441 -231.465992)
		(end 88.80221 -231.39019)
		(width 0.0889)
		(layer "B.Cu")
		(net "H_PMAX_TRIGGER_IO_CPU1")
	)
	(arc
		(start 97.26041 -231.39019)
		(mid 97.073212 -231.340047)
		(end 96.886014 -231.39019)
		(width 0.0889)
		(layer "B.Cu")
		(net "H_PMAX_TRIGGER_IO_CPU1")
	)
	(arc
		(start 92.56141 -231.39019)
		(mid 92.374212 -231.340047)
		(end 92.187014 -231.39019)
		(width 0.0889)
		(layer "B.Cu")
		(net "H_PMAX_TRIGGER_IO_CPU1")
	)
	(arc
		(start 90.68181 -231.39019)
		(mid 90.494612 -231.340047)
		(end 90.307414 -231.39019)
		(width 0.0889)
		(layer "B.Cu")
		(net "H_PMAX_TRIGGER_IO_CPU1")
	)
	(arc
		(start 94.441264 -231.39019)
		(mid 94.254066 -231.340047)
		(end 94.066868 -231.39019)
		(width 0.0889)
		(layer "B.Cu")
		(net "H_PMAX_TRIGGER_IO_CPU1")
	)
	(arc
		(start 98.20021 -231.39019)
		(mid 98.013012 -231.340047)
		(end 97.825814 -231.39019)
		(width 0.0889)
		(layer "B.Cu")
		(net "H_PMAX_TRIGGER_IO_CPU1")
	)
	(arc
		(start 95.931482 -231.398826)
		(mid 95.655041 -231.465992)
		(end 95.38081 -231.39019)
		(width 0.0889)
		(layer "B.Cu")
		(net "H_PMAX_TRIGGER_IO_CPU1")
	)
	(arc
		(start 104.309164 -232.204006)
		(mid 104.121966 -232.153863)
		(end 103.934768 -232.204006)
		(width 0.0889)
		(layer "B.Cu")
		(net "H_PMAX_TRIGGER_IO_CPU1")
	)
	(arc
		(start 94.996 -231.396286)
		(mid 94.717822 -231.465978)
		(end 94.441264 -231.39019)
		(width 0.0889)
		(layer "B.Cu")
		(net "H_PMAX_TRIGGER_IO_CPU1")
	)
	(arc
		(start 96.871282 -231.398826)
		(mid 96.594841 -231.465992)
		(end 96.32061 -231.39019)
		(width 0.0889)
		(layer "B.Cu")
		(net "H_PMAX_TRIGGER_IO_CPU1")
	)
	(arc
		(start 98.750882 -231.398826)
		(mid 98.474441 -231.465992)
		(end 98.20021 -231.39019)
		(width 0.0889)
		(layer "B.Cu")
		(net "H_PMAX_TRIGGER_IO_CPU1")
	)
	(arc
		(start 93.112082 -231.398826)
		(mid 92.835641 -231.465992)
		(end 92.56141 -231.39019)
		(width 0.0889)
		(layer "B.Cu")
		(net "H_PMAX_TRIGGER_IO_CPU1")
	)
	(arc
		(start 92.172282 -231.398826)
		(mid 91.895841 -231.465992)
		(end 91.62161 -231.39019)
		(width 0.0889)
		(layer "B.Cu")
		(net "H_PMAX_TRIGGER_IO_CPU1")
	)
	(arc
		(start 88.4174 -231.396286)
		(mid 88.139222 -231.465978)
		(end 87.862664 -231.39019)
		(width 0.0889)
		(layer "B.Cu")
		(net "H_PMAX_TRIGGER_IO_CPU1")
	)
	(arc
		(start 90.292682 -231.398826)
		(mid 90.016241 -231.465992)
		(end 89.74201 -231.39019)
		(width 0.0889)
		(layer "B.Cu")
		(net "H_PMAX_TRIGGER_IO_CPU1")
	)
	(segment
		(start 353.001834 -233.06405)
		(end 353.001834 -232.528364)
		(width 0.12954)
		(layer "F.Cu")
		(net "H_PMAX_TRIGGER_IO_CPU0")
	)
	(segment
		(start 353.00158 -233.064304)
		(end 353.001834 -233.06405)
		(width 0.12954)
		(layer "F.Cu")
		(net "H_PMAX_TRIGGER_IO_CPU0")
	)
	(via
		(at 353.001834 -232.528364)
		(size 0.4572)
		(drill 0.2032)
		(layers "F.Cu" "B.Cu")
		(net "H_PMAX_TRIGGER_IO_CPU0")
	)
	(via
		(at 317.938658 -230.50119)
		(size 0.6604)
		(drill 0.3302)
		(layers "F.Cu" "B.Cu")
		(net "H_PMAX_TRIGGER_IO_CPU0")
	)
	(segment
		(start 346.705682 -231.39019)
		(end 346.69095 -231.398826)
		(width 0.0889)
		(layer "B.Cu")
		(net "H_PMAX_TRIGGER_IO_CPU0")
	)
	(segment
		(start 352.263964 -232.212642)
		(end 352.249232 -232.204006)
		(width 0.0889)
		(layer "B.Cu")
		(net "H_PMAX_TRIGGER_IO_CPU0")
	)
	(segment
		(start 341.066882 -231.39019)
		(end 341.05215 -231.398826)
		(width 0.0889)
		(layer "B.Cu")
		(net "H_PMAX_TRIGGER_IO_CPU0")
	)
	(segment
		(start 353.001834 -232.528364)
		(end 352.263964 -232.212642)
		(width 0.0889)
		(layer "B.Cu")
		(net "H_PMAX_TRIGGER_IO_CPU0")
	)
	(segment
		(start 335.615534 -231.33939)
		(end 334.341978 -231.33939)
		(width 0.0889)
		(layer "B.Cu")
		(net "H_PMAX_TRIGGER_IO_CPU0")
	)
	(segment
		(start 342.946482 -231.39019)
		(end 342.936068 -231.396286)
		(width 0.0889)
		(layer "B.Cu")
		(net "H_PMAX_TRIGGER_IO_CPU0")
	)
	(segment
		(start 349.525082 -231.39019)
		(end 349.514668 -231.396286)
		(width 0.0889)
		(layer "B.Cu")
		(net "H_PMAX_TRIGGER_IO_CPU0")
	)
	(segment
		(start 340.127082 -231.39019)
		(end 340.11235 -231.398826)
		(width 0.0889)
		(layer "B.Cu")
		(net "H_PMAX_TRIGGER_IO_CPU0")
	)
	(segment
		(start 338.247482 -231.39019)
		(end 338.23275 -231.398826)
		(width 0.0889)
		(layer "B.Cu")
		(net "H_PMAX_TRIGGER_IO_CPU0")
	)
	(segment
		(start 350.369632 -232.204006)
		(end 350.363536 -232.20045)
		(width 0.0889)
		(layer "B.Cu")
		(net "H_PMAX_TRIGGER_IO_CPU0")
	)
	(segment
		(start 350.384364 -232.212642)
		(end 350.369632 -232.204006)
		(width 0.0889)
		(layer "B.Cu")
		(net "H_PMAX_TRIGGER_IO_CPU0")
	)
	(segment
		(start 348.585536 -231.39019)
		(end 348.575122 -231.396286)
		(width 0.0889)
		(layer "B.Cu")
		(net "H_PMAX_TRIGGER_IO_CPU0")
	)
	(segment
		(start 344.826082 -231.39019)
		(end 344.81135 -231.398826)
		(width 0.0889)
		(layer "B.Cu")
		(net "H_PMAX_TRIGGER_IO_CPU0")
	)
	(segment
		(start 343.886282 -231.39019)
		(end 343.87155 -231.398826)
		(width 0.0889)
		(layer "B.Cu")
		(net "H_PMAX_TRIGGER_IO_CPU0")
	)
	(segment
		(start 334.100678 -231.58069)
		(end 333.691738 -231.58069)
		(width 0.0889)
		(layer "B.Cu")
		(net "H_PMAX_TRIGGER_IO_CPU0")
	)
	(segment
		(start 317.938658 -230.50119)
		(end 315.684408 -230.50119)
		(width 0.12954)
		(layer "B.Cu")
		(net "H_PMAX_TRIGGER_IO_CPU0")
	)
	(segment
		(start 351.324164 -232.212642)
		(end 351.309432 -232.204006)
		(width 0.0889)
		(layer "B.Cu")
		(net "H_PMAX_TRIGGER_IO_CPU0")
	)
	(segment
		(start 334.341978 -231.33939)
		(end 334.100678 -231.58069)
		(width 0.0889)
		(layer "B.Cu")
		(net "H_PMAX_TRIGGER_IO_CPU0")
	)
	(segment
		(start 322.7324 -230.50119)
		(end 317.938658 -230.50119)
		(width 0.12954)
		(layer "B.Cu")
		(net "H_PMAX_TRIGGER_IO_CPU0")
	)
	(segment
		(start 336.367882 -231.39019)
		(end 336.357468 -231.396286)
		(width 0.0889)
		(layer "B.Cu")
		(net "H_PMAX_TRIGGER_IO_CPU0")
	)
	(segment
		(start 342.006936 -231.39019)
		(end 341.996522 -231.396286)
		(width 0.0889)
		(layer "B.Cu")
		(net "H_PMAX_TRIGGER_IO_CPU0")
	)
	(segment
		(start 323.8119 -231.58069)
		(end 322.7324 -230.50119)
		(width 0.12954)
		(layer "B.Cu")
		(net "H_PMAX_TRIGGER_IO_CPU0")
	)
	(segment
		(start 333.691738 -231.58069)
		(end 323.8119 -231.58069)
		(width 0.12954)
		(layer "B.Cu")
		(net "H_PMAX_TRIGGER_IO_CPU0")
	)
	(segment
		(start 337.307682 -231.39019)
		(end 337.29295 -231.398826)
		(width 0.0889)
		(layer "B.Cu")
		(net "H_PMAX_TRIGGER_IO_CPU0")
	)
	(segment
		(start 347.645482 -231.39019)
		(end 347.63075 -231.398826)
		(width 0.0889)
		(layer "B.Cu")
		(net "H_PMAX_TRIGGER_IO_CPU0")
	)
	(segment
		(start 349.908368 -231.39527)
		(end 349.899478 -231.39019)
		(width 0.0889)
		(layer "B.Cu")
		(net "H_PMAX_TRIGGER_IO_CPU0")
	)
	(arc
		(start 338.621878 -231.39019)
		(mid 338.43468 -231.340047)
		(end 338.247482 -231.39019)
		(width 0.0889)
		(layer "B.Cu")
		(net "H_PMAX_TRIGGER_IO_CPU0")
	)
	(arc
		(start 341.441278 -231.39019)
		(mid 341.25408 -231.340047)
		(end 341.066882 -231.39019)
		(width 0.0889)
		(layer "B.Cu")
		(net "H_PMAX_TRIGGER_IO_CPU0")
	)
	(arc
		(start 340.501478 -231.39019)
		(mid 340.31428 -231.340047)
		(end 340.127082 -231.39019)
		(width 0.0889)
		(layer "B.Cu")
		(net "H_PMAX_TRIGGER_IO_CPU0")
	)
	(arc
		(start 343.320878 -231.39019)
		(mid 343.13368 -231.340047)
		(end 342.946482 -231.39019)
		(width 0.0889)
		(layer "B.Cu")
		(net "H_PMAX_TRIGGER_IO_CPU0")
	)
	(arc
		(start 350.08693 -231.714548)
		(mid 350.039251 -231.531648)
		(end 349.908368 -231.39527)
		(width 0.0889)
		(layer "B.Cu")
		(net "H_PMAX_TRIGGER_IO_CPU0")
	)
	(arc
		(start 350.935036 -232.204006)
		(mid 350.660837 -232.279841)
		(end 350.384364 -232.212642)
		(width 0.0889)
		(layer "B.Cu")
		(net "H_PMAX_TRIGGER_IO_CPU0")
	)
	(arc
		(start 351.309432 -232.204006)
		(mid 351.122234 -232.153863)
		(end 350.935036 -232.204006)
		(width 0.0889)
		(layer "B.Cu")
		(net "H_PMAX_TRIGGER_IO_CPU0")
	)
	(arc
		(start 349.899478 -231.39019)
		(mid 349.71228 -231.340047)
		(end 349.525082 -231.39019)
		(width 0.0889)
		(layer "B.Cu")
		(net "H_PMAX_TRIGGER_IO_CPU0")
	)
	(arc
		(start 342.381332 -231.39019)
		(mid 342.194134 -231.340047)
		(end 342.006936 -231.39019)
		(width 0.0889)
		(layer "B.Cu")
		(net "H_PMAX_TRIGGER_IO_CPU0")
	)
	(arc
		(start 339.561678 -231.39019)
		(mid 339.37448 -231.340047)
		(end 339.187282 -231.39019)
		(width 0.0889)
		(layer "B.Cu")
		(net "H_PMAX_TRIGGER_IO_CPU0")
	)
	(arc
		(start 335.802732 -231.39019)
		(mid 335.712476 -231.352468)
		(end 335.615534 -231.33939)
		(width 0.0889)
		(layer "B.Cu")
		(net "H_PMAX_TRIGGER_IO_CPU0")
	)
	(arc
		(start 344.260678 -231.39019)
		(mid 344.07348 -231.340047)
		(end 343.886282 -231.39019)
		(width 0.0889)
		(layer "B.Cu")
		(net "H_PMAX_TRIGGER_IO_CPU0")
	)
	(arc
		(start 345.200478 -231.39019)
		(mid 345.01328 -231.340047)
		(end 344.826082 -231.39019)
		(width 0.0889)
		(layer "B.Cu")
		(net "H_PMAX_TRIGGER_IO_CPU0")
	)
	(arc
		(start 349.514668 -231.396286)
		(mid 349.23649 -231.465978)
		(end 348.959932 -231.39019)
		(width 0.0889)
		(layer "B.Cu")
		(net "H_PMAX_TRIGGER_IO_CPU0")
	)
	(arc
		(start 348.959932 -231.39019)
		(mid 348.772734 -231.340047)
		(end 348.585536 -231.39019)
		(width 0.0889)
		(layer "B.Cu")
		(net "H_PMAX_TRIGGER_IO_CPU0")
	)
	(arc
		(start 342.936068 -231.396286)
		(mid 342.65789 -231.465978)
		(end 342.381332 -231.39019)
		(width 0.0889)
		(layer "B.Cu")
		(net "H_PMAX_TRIGGER_IO_CPU0")
	)
	(arc
		(start 339.187282 -231.39019)
		(mid 338.90458 -231.465932)
		(end 338.621878 -231.39019)
		(width 0.0889)
		(layer "B.Cu")
		(net "H_PMAX_TRIGGER_IO_CPU0")
	)
	(arc
		(start 340.11235 -231.398826)
		(mid 339.835909 -231.465992)
		(end 339.561678 -231.39019)
		(width 0.0889)
		(layer "B.Cu")
		(net "H_PMAX_TRIGGER_IO_CPU0")
	)
	(arc
		(start 336.742278 -231.39019)
		(mid 336.55508 -231.340047)
		(end 336.367882 -231.39019)
		(width 0.0889)
		(layer "B.Cu")
		(net "H_PMAX_TRIGGER_IO_CPU0")
	)
	(arc
		(start 344.81135 -231.398826)
		(mid 344.534909 -231.465992)
		(end 344.260678 -231.39019)
		(width 0.0889)
		(layer "B.Cu")
		(net "H_PMAX_TRIGGER_IO_CPU0")
	)
	(arc
		(start 348.019878 -231.39019)
		(mid 347.83268 -231.340047)
		(end 347.645482 -231.39019)
		(width 0.0889)
		(layer "B.Cu")
		(net "H_PMAX_TRIGGER_IO_CPU0")
	)
	(arc
		(start 346.140278 -231.39019)
		(mid 345.95308 -231.340047)
		(end 345.765882 -231.39019)
		(width 0.0889)
		(layer "B.Cu")
		(net "H_PMAX_TRIGGER_IO_CPU0")
	)
	(arc
		(start 336.357468 -231.396286)
		(mid 336.07929 -231.465978)
		(end 335.802732 -231.39019)
		(width 0.0889)
		(layer "B.Cu")
		(net "H_PMAX_TRIGGER_IO_CPU0")
	)
	(arc
		(start 346.69095 -231.398826)
		(mid 346.414509 -231.465992)
		(end 346.140278 -231.39019)
		(width 0.0889)
		(layer "B.Cu")
		(net "H_PMAX_TRIGGER_IO_CPU0")
	)
	(arc
		(start 341.996522 -231.396286)
		(mid 341.71809 -231.4661)
		(end 341.441278 -231.39019)
		(width 0.0889)
		(layer "B.Cu")
		(net "H_PMAX_TRIGGER_IO_CPU0")
	)
	(arc
		(start 347.63075 -231.398826)
		(mid 347.354309 -231.465992)
		(end 347.080078 -231.39019)
		(width 0.0889)
		(layer "B.Cu")
		(net "H_PMAX_TRIGGER_IO_CPU0")
	)
	(arc
		(start 347.080078 -231.39019)
		(mid 346.89288 -231.340047)
		(end 346.705682 -231.39019)
		(width 0.0889)
		(layer "B.Cu")
		(net "H_PMAX_TRIGGER_IO_CPU0")
	)
	(arc
		(start 352.249232 -232.204006)
		(mid 352.062034 -232.153863)
		(end 351.874836 -232.204006)
		(width 0.0889)
		(layer "B.Cu")
		(net "H_PMAX_TRIGGER_IO_CPU0")
	)
	(arc
		(start 345.765882 -231.39019)
		(mid 345.48318 -231.465932)
		(end 345.200478 -231.39019)
		(width 0.0889)
		(layer "B.Cu")
		(net "H_PMAX_TRIGGER_IO_CPU0")
	)
	(arc
		(start 350.363536 -232.20045)
		(mid 350.160949 -231.994099)
		(end 350.08693 -231.714548)
		(width 0.0889)
		(layer "B.Cu")
		(net "H_PMAX_TRIGGER_IO_CPU0")
	)
	(arc
		(start 348.575122 -231.396286)
		(mid 348.29669 -231.4661)
		(end 348.019878 -231.39019)
		(width 0.0889)
		(layer "B.Cu")
		(net "H_PMAX_TRIGGER_IO_CPU0")
	)
	(arc
		(start 337.29295 -231.398826)
		(mid 337.016509 -231.465992)
		(end 336.742278 -231.39019)
		(width 0.0889)
		(layer "B.Cu")
		(net "H_PMAX_TRIGGER_IO_CPU0")
	)
	(arc
		(start 341.05215 -231.398826)
		(mid 340.775709 -231.465992)
		(end 340.501478 -231.39019)
		(width 0.0889)
		(layer "B.Cu")
		(net "H_PMAX_TRIGGER_IO_CPU0")
	)
	(arc
		(start 351.874836 -232.204006)
		(mid 351.600637 -232.279841)
		(end 351.324164 -232.212642)
		(width 0.0889)
		(layer "B.Cu")
		(net "H_PMAX_TRIGGER_IO_CPU0")
	)
	(arc
		(start 343.87155 -231.398826)
		(mid 343.595109 -231.465992)
		(end 343.320878 -231.39019)
		(width 0.0889)
		(layer "B.Cu")
		(net "H_PMAX_TRIGGER_IO_CPU0")
	)
	(arc
		(start 338.23275 -231.398826)
		(mid 337.956309 -231.465992)
		(end 337.682078 -231.39019)
		(width 0.0889)
		(layer "B.Cu")
		(net "H_PMAX_TRIGGER_IO_CPU0")
	)
	(arc
		(start 337.682078 -231.39019)
		(mid 337.49488 -231.340047)
		(end 337.307682 -231.39019)
		(width 0.0889)
		(layer "B.Cu")
		(net "H_PMAX_TRIGGER_IO_CPU0")
	)
	(segment
		(start 347.534484 -30.75686)
		(end 347.534484 -34.546794)
		(width 0.12954)
		(layer "F.Cu")
		(net "H_DBP_PREQ_N_PCH")
	)
	(segment
		(start 372.00332 -50.691034)
		(end 372.00332 -40.771318)
		(width 0.12954)
		(layer "F.Cu")
		(net "H_DBP_PREQ_N_PCH")
	)
	(segment
		(start 346.126816 -35.485324)
		(end 345.896438 -35.485324)
		(width 0.0889)
		(layer "F.Cu")
		(net "H_DBP_PREQ_N_PCH")
	)
	(segment
		(start 344.403426 -36.978336)
		(end 344.403426 -38.050216)
		(width 0.0889)
		(layer "F.Cu")
		(net "H_DBP_PREQ_N_PCH")
	)
	(segment
		(start 348.554294 -27.660854)
		(end 348.554294 -29.73705)
		(width 0.12954)
		(layer "F.Cu")
		(net "H_DBP_PREQ_N_PCH")
	)
	(segment
		(start 366.8522 -33.7947)
		(end 354.792788 -21.735288)
		(width 0.12954)
		(layer "F.Cu")
		(net "H_DBP_PREQ_N_PCH")
	)
	(segment
		(start 371.490494 -51.20386)
		(end 372.00332 -50.691034)
		(width 0.12954)
		(layer "F.Cu")
		(net "H_DBP_PREQ_N_PCH")
	)
	(segment
		(start 374.42648 -67.554348)
		(end 374.56364 -67.417188)
		(width 0.12954)
		(layer "F.Cu")
		(net "H_DBP_PREQ_N_PCH")
	)
	(segment
		(start 370.81333 -39.581328)
		(end 368.09426 -39.581328)
		(width 0.12954)
		(layer "F.Cu")
		(net "H_DBP_PREQ_N_PCH")
	)
	(segment
		(start 350.977708 -22.225)
		(end 350.972628 -22.225)
		(width 0.12954)
		(layer "F.Cu")
		(net "H_DBP_PREQ_N_PCH")
	)
	(segment
		(start 354.792788 -21.735288)
		(end 351.46742 -21.735288)
		(width 0.12954)
		(layer "F.Cu")
		(net "H_DBP_PREQ_N_PCH")
	)
	(segment
		(start 374.35028 -67.554348)
		(end 374.42648 -67.554348)
		(width 0.12954)
		(layer "F.Cu")
		(net "H_DBP_PREQ_N_PCH")
	)
	(segment
		(start 348.554294 -29.73705)
		(end 347.534484 -30.75686)
		(width 0.12954)
		(layer "F.Cu")
		(net "H_DBP_PREQ_N_PCH")
	)
	(segment
		(start 374.56364 -67.417188)
		(end 374.56364 -66.898012)
		(width 0.12954)
		(layer "F.Cu")
		(net "H_DBP_PREQ_N_PCH")
	)
	(segment
		(start 371.602 -40.369998)
		(end 370.81333 -39.581328)
		(width 0.12954)
		(layer "F.Cu")
		(net "H_DBP_PREQ_N_PCH")
	)
	(segment
		(start 371.490494 -52.319428)
		(end 371.490494 -51.20386)
		(width 0.12954)
		(layer "F.Cu")
		(net "H_DBP_PREQ_N_PCH")
	)
	(segment
		(start 350.972628 -22.225)
		(end 349.522542 -23.675086)
		(width 0.12954)
		(layer "F.Cu")
		(net "H_DBP_PREQ_N_PCH")
	)
	(segment
		(start 346.595954 -35.485324)
		(end 346.126816 -35.485324)
		(width 0.12954)
		(layer "F.Cu")
		(net "H_DBP_PREQ_N_PCH")
	)
	(segment
		(start 351.46742 -21.735288)
		(end 350.977708 -22.225)
		(width 0.12954)
		(layer "F.Cu")
		(net "H_DBP_PREQ_N_PCH")
	)
	(segment
		(start 368.09426 -39.581328)
		(end 366.8522 -38.339268)
		(width 0.12954)
		(layer "F.Cu")
		(net "H_DBP_PREQ_N_PCH")
	)
	(segment
		(start 366.8522 -38.339268)
		(end 366.8522 -33.7947)
		(width 0.12954)
		(layer "F.Cu")
		(net "H_DBP_PREQ_N_PCH")
	)
	(segment
		(start 349.522542 -23.675086)
		(end 349.522542 -26.692606)
		(width 0.12954)
		(layer "F.Cu")
		(net "H_DBP_PREQ_N_PCH")
	)
	(segment
		(start 349.522542 -26.692606)
		(end 348.554294 -27.660854)
		(width 0.12954)
		(layer "F.Cu")
		(net "H_DBP_PREQ_N_PCH")
	)
	(segment
		(start 347.534484 -34.546794)
		(end 346.595954 -35.485324)
		(width 0.12954)
		(layer "F.Cu")
		(net "H_DBP_PREQ_N_PCH")
	)
	(segment
		(start 345.896438 -35.485324)
		(end 344.403426 -36.978336)
		(width 0.0889)
		(layer "F.Cu")
		(net "H_DBP_PREQ_N_PCH")
	)
	(segment
		(start 372.00332 -40.771318)
		(end 371.602 -40.369998)
		(width 0.12954)
		(layer "F.Cu")
		(net "H_DBP_PREQ_N_PCH")
	)
	(via
		(at 371.490494 -52.319428)
		(size 0.508)
		(drill 0.254)
		(layers "F.Cu" "B.Cu")
		(net "H_DBP_PREQ_N_PCH")
	)
	(via
		(at 374.35028 -67.554348)
		(size 0.508)
		(drill 0.254)
		(layers "F.Cu" "B.Cu")
		(net "H_DBP_PREQ_N_PCH")
	)
	(segment
		(start 374.32488 -67.528948)
		(end 374.32488 -65.522348)
		(width 0.127)
		(layer "In2.Cu")
		(net "H_DBP_PREQ_N_PCH")
	)
	(segment
		(start 373.20728 -54.219094)
		(end 371.490494 -52.502308)
		(width 0.127)
		(layer "In2.Cu")
		(net "H_DBP_PREQ_N_PCH")
	)
	(segment
		(start 374.32488 -65.522348)
		(end 373.20728 -64.404748)
		(width 0.127)
		(layer "In2.Cu")
		(net "H_DBP_PREQ_N_PCH")
	)
	(segment
		(start 371.490494 -52.502308)
		(end 371.490494 -52.319428)
		(width 0.127)
		(layer "In2.Cu")
		(net "H_DBP_PREQ_N_PCH")
	)
	(segment
		(start 374.35028 -67.554348)
		(end 374.32488 -67.528948)
		(width 0.127)
		(layer "In2.Cu")
		(net "H_DBP_PREQ_N_PCH")
	)
	(segment
		(start 373.20728 -64.404748)
		(end 373.20728 -54.219094)
		(width 0.127)
		(layer "In2.Cu")
		(net "H_DBP_PREQ_N_PCH")
	)
	(segment
		(start 344.44686 -39.486332)
		(end 344.63355 -39.673022)
		(width 0.12954)
		(layer "F.Cu")
		(net "H_DBP_PRDY_N_PCH")
	)
	(segment
		(start 344.63355 -39.673022)
		(end 344.63355 -39.992046)
		(width 0.12954)
		(layer "F.Cu")
		(net "H_DBP_PRDY_N_PCH")
	)
	(segment
		(start 374.56364 -64.866012)
		(end 374.56364 -64.231012)
		(width 0.12954)
		(layer "F.Cu")
		(net "H_DBP_PRDY_N_PCH")
	)
	(segment
		(start 374.56364 -64.866012)
		(end 377.06554 -64.866012)
		(width 0.12954)
		(layer "F.Cu")
		(net "H_DBP_PRDY_N_PCH")
	)
	(segment
		(start 344.414094 -39.486332)
		(end 344.44686 -39.486332)
		(width 0.12954)
		(layer "F.Cu")
		(net "H_DBP_PRDY_N_PCH")
	)
	(via
		(at 374.56364 -64.231012)
		(size 0.508)
		(drill 0.254)
		(layers "F.Cu" "B.Cu")
		(net "H_DBP_PRDY_N_PCH")
	)
	(via
		(at 344.414094 -39.486332)
		(size 0.4572)
		(drill 0.2032)
		(layers "F.Cu" "B.Cu")
		(net "H_DBP_PRDY_N_PCH")
	)
	(segment
		(start 355.85146 -55.857648)
		(end 354.457 -55.857648)
		(width 0.127)
		(layer "In6.Cu")
		(net "H_DBP_PRDY_N_PCH")
	)
	(segment
		(start 346.29852 -40.467788)
		(end 345.317064 -39.486332)
		(width 0.127)
		(layer "In6.Cu")
		(net "H_DBP_PRDY_N_PCH")
	)
	(segment
		(start 374.56364 -64.231012)
		(end 373.406416 -63.073788)
		(width 0.127)
		(layer "In6.Cu")
		(net "H_DBP_PRDY_N_PCH")
	)
	(segment
		(start 359.01884 -58.125868)
		(end 357.81488 -56.921908)
		(width 0.127)
		(layer "In6.Cu")
		(net "H_DBP_PRDY_N_PCH")
	)
	(segment
		(start 356.91572 -56.921908)
		(end 355.85146 -55.857648)
		(width 0.127)
		(layer "In6.Cu")
		(net "H_DBP_PRDY_N_PCH")
	)
	(segment
		(start 373.406416 -63.073788)
		(end 365.4552 -63.073788)
		(width 0.127)
		(layer "In6.Cu")
		(net "H_DBP_PRDY_N_PCH")
	)
	(segment
		(start 354.457 -55.857648)
		(end 346.29852 -47.699168)
		(width 0.127)
		(layer "In6.Cu")
		(net "H_DBP_PRDY_N_PCH")
	)
	(segment
		(start 345.317064 -39.486332)
		(end 344.414094 -39.486332)
		(width 0.127)
		(layer "In6.Cu")
		(net "H_DBP_PRDY_N_PCH")
	)
	(segment
		(start 365.4552 -63.073788)
		(end 360.50728 -58.125868)
		(width 0.127)
		(layer "In6.Cu")
		(net "H_DBP_PRDY_N_PCH")
	)
	(segment
		(start 346.29852 -47.699168)
		(end 346.29852 -40.467788)
		(width 0.127)
		(layer "In6.Cu")
		(net "H_DBP_PRDY_N_PCH")
	)
	(segment
		(start 357.81488 -56.921908)
		(end 356.91572 -56.921908)
		(width 0.127)
		(layer "In6.Cu")
		(net "H_DBP_PRDY_N_PCH")
	)
	(segment
		(start 360.50728 -58.125868)
		(end 359.01884 -58.125868)
		(width 0.127)
		(layer "In6.Cu")
		(net "H_DBP_PRDY_N_PCH")
	)
	(segment
		(start 114.28984 -99.634802)
		(end 114.569748 -99.354894)
		(width 0.12954)
		(layer "F.Cu")
		(net "H_CPU_RMCA_LVC1_R_N")
	)
	(segment
		(start 114.28984 -100.62464)
		(end 114.28984 -99.634802)
		(width 0.12954)
		(layer "F.Cu")
		(net "H_CPU_RMCA_LVC1_R_N")
	)
	(segment
		(start 114.569748 -99.354894)
		(end 114.569748 -98.425762)
		(width 0.12954)
		(layer "F.Cu")
		(net "H_CPU_RMCA_LVC1_R_N")
	)
	(segment
		(start 114.569748 -100.904548)
		(end 114.28984 -100.62464)
		(width 0.12954)
		(layer "F.Cu")
		(net "H_CPU_RMCA_LVC1_R_N")
	)
	(via
		(at 114.569748 -100.904548)
		(size 0.508)
		(drill 0.254)
		(layers "F.Cu" "B.Cu")
		(net "H_CPU_RMCA_LVC1_R_N")
	)
	(via
		(at 118.65102 -152.430988)
		(size 0.508)
		(drill 0.254)
		(layers "F.Cu" "B.Cu")
		(net "H_CPU_RMCA_LVC1_R_N")
	)
	(via
		(at 263.71804 -152.723088)
		(size 0.508)
		(drill 0.254)
		(layers "F.Cu" "B.Cu")
		(net "H_CPU_RMCA_LVC1_R_N")
	)
	(segment
		(start 84.974684 -187.635642)
		(end 85.114638 -187.495688)
		(width 0.12954)
		(layer "B.Cu")
		(net "H_CPU_RMCA_LVC1_R_N")
	)
	(segment
		(start 85.114638 -187.495688)
		(end 85.114638 -186.411108)
		(width 0.12954)
		(layer "B.Cu")
		(net "H_CPU_RMCA_LVC1_R_N")
	)
	(segment
		(start 322.90512 -186.604402)
		(end 323.407278 -187.10656)
		(width 0.12954)
		(layer "B.Cu")
		(net "H_CPU_RMCA_LVC1_R_N")
	)
	(segment
		(start 84.693252 -182.61203)
		(end 85.835998 -183.754776)
		(width 0.12954)
		(layer "B.Cu")
		(net "H_CPU_RMCA_LVC1_R_N")
	)
	(segment
		(start 323.661278 -188.08446)
		(end 323.661278 -187.36056)
		(width 0.12954)
		(layer "B.Cu")
		(net "H_CPU_RMCA_LVC1_R_N")
	)
	(segment
		(start 263.9187 -154.587448)
		(end 263.9187 -157.503114)
		(width 0.12954)
		(layer "B.Cu")
		(net "H_CPU_RMCA_LVC1_R_N")
	)
	(segment
		(start 322.90512 -184.510426)
		(end 322.90512 -186.604402)
		(width 0.12954)
		(layer "B.Cu")
		(net "H_CPU_RMCA_LVC1_R_N")
	)
	(segment
		(start 85.114638 -186.411108)
		(end 85.122004 -186.403742)
		(width 0.12954)
		(layer "B.Cu")
		(net "H_CPU_RMCA_LVC1_R_N")
	)
	(segment
		(start 109.715554 -152.430988)
		(end 85.835998 -176.310544)
		(width 0.12954)
		(layer "B.Cu")
		(net "H_CPU_RMCA_LVC1_R_N")
	)
	(segment
		(start 276.956774 -170.541188)
		(end 308.935882 -170.541188)
		(width 0.12954)
		(layer "B.Cu")
		(net "H_CPU_RMCA_LVC1_R_N")
	)
	(segment
		(start 85.835998 -185.89879)
		(end 85.416898 -186.31789)
		(width 0.12954)
		(layer "B.Cu")
		(net "H_CPU_RMCA_LVC1_R_N")
	)
	(segment
		(start 85.835998 -176.310544)
		(end 85.835998 -180.08727)
		(width 0.12954)
		(layer "B.Cu")
		(net "H_CPU_RMCA_LVC1_R_N")
	)
	(segment
		(start 308.935882 -170.541188)
		(end 322.90512 -184.510426)
		(width 0.12954)
		(layer "B.Cu")
		(net "H_CPU_RMCA_LVC1_R_N")
	)
	(segment
		(start 118.65102 -152.430988)
		(end 109.715554 -152.430988)
		(width 0.12954)
		(layer "B.Cu")
		(net "H_CPU_RMCA_LVC1_R_N")
	)
	(segment
		(start 85.835998 -183.754776)
		(end 85.835998 -185.89879)
		(width 0.12954)
		(layer "B.Cu")
		(net "H_CPU_RMCA_LVC1_R_N")
	)
	(segment
		(start 263.71804 -152.723088)
		(end 263.71804 -154.386788)
		(width 0.12954)
		(layer "B.Cu")
		(net "H_CPU_RMCA_LVC1_R_N")
	)
	(segment
		(start 263.71804 -154.386788)
		(end 263.9187 -154.587448)
		(width 0.12954)
		(layer "B.Cu")
		(net "H_CPU_RMCA_LVC1_R_N")
	)
	(segment
		(start 84.693252 -181.230016)
		(end 84.693252 -182.61203)
		(width 0.12954)
		(layer "B.Cu")
		(net "H_CPU_RMCA_LVC1_R_N")
	)
	(segment
		(start 85.207856 -186.31789)
		(end 85.122004 -186.403742)
		(width 0.12954)
		(layer "B.Cu")
		(net "H_CPU_RMCA_LVC1_R_N")
	)
	(segment
		(start 85.416898 -186.31789)
		(end 85.207856 -186.31789)
		(width 0.12954)
		(layer "B.Cu")
		(net "H_CPU_RMCA_LVC1_R_N")
	)
	(segment
		(start 85.835998 -180.08727)
		(end 84.693252 -181.230016)
		(width 0.12954)
		(layer "B.Cu")
		(net "H_CPU_RMCA_LVC1_R_N")
	)
	(segment
		(start 263.9187 -157.503114)
		(end 276.956774 -170.541188)
		(width 0.12954)
		(layer "B.Cu")
		(net "H_CPU_RMCA_LVC1_R_N")
	)
	(segment
		(start 323.661278 -187.36056)
		(end 323.407278 -187.10656)
		(width 0.12954)
		(layer "B.Cu")
		(net "H_CPU_RMCA_LVC1_R_N")
	)
	(segment
		(start 118.65102 -152.430988)
		(end 119.081296 -152.000712)
		(width 0.127)
		(layer "In2.Cu")
		(net "H_CPU_RMCA_LVC1_R_N")
	)
	(segment
		(start 117.80012 -106.551476)
		(end 117.80012 -104.369108)
		(width 0.127)
		(layer "In2.Cu")
		(net "H_CPU_RMCA_LVC1_R_N")
	)
	(segment
		(start 117.239034 -113.523014)
		(end 117.239034 -107.112562)
		(width 0.127)
		(layer "In2.Cu")
		(net "H_CPU_RMCA_LVC1_R_N")
	)
	(segment
		(start 117.239034 -107.112562)
		(end 117.80012 -106.551476)
		(width 0.127)
		(layer "In2.Cu")
		(net "H_CPU_RMCA_LVC1_R_N")
	)
	(segment
		(start 119.081296 -115.365276)
		(end 117.239034 -113.523014)
		(width 0.127)
		(layer "In2.Cu")
		(net "H_CPU_RMCA_LVC1_R_N")
	)
	(segment
		(start 114.569748 -102.934516)
		(end 114.569748 -100.904548)
		(width 0.127)
		(layer "In2.Cu")
		(net "H_CPU_RMCA_LVC1_R_N")
	)
	(segment
		(start 117.094 -103.662988)
		(end 115.29822 -103.662988)
		(width 0.127)
		(layer "In2.Cu")
		(net "H_CPU_RMCA_LVC1_R_N")
	)
	(segment
		(start 115.29822 -103.662988)
		(end 114.569748 -102.934516)
		(width 0.127)
		(layer "In2.Cu")
		(net "H_CPU_RMCA_LVC1_R_N")
	)
	(segment
		(start 119.081296 -152.000712)
		(end 119.081296 -115.365276)
		(width 0.127)
		(layer "In2.Cu")
		(net "H_CPU_RMCA_LVC1_R_N")
	)
	(segment
		(start 117.80012 -104.369108)
		(end 117.094 -103.662988)
		(width 0.127)
		(layer "In2.Cu")
		(net "H_CPU_RMCA_LVC1_R_N")
	)
	(segment
		(start 135.03148 -149.101048)
		(end 134.47776 -149.654768)
		(width 0.127)
		(layer "In13.Cu")
		(net "H_CPU_RMCA_LVC1_R_N")
	)
	(segment
		(start 118.65102 -145.379694)
		(end 118.65102 -152.430988)
		(width 0.127)
		(layer "In13.Cu")
		(net "H_CPU_RMCA_LVC1_R_N")
	)
	(segment
		(start 140.67028 -147.297394)
		(end 140.67028 -148.100288)
		(width 0.127)
		(layer "In13.Cu")
		(net "H_CPU_RMCA_LVC1_R_N")
	)
	(segment
		(start 139.28344 -150.508208)
		(end 137.65784 -150.508208)
		(width 0.127)
		(layer "In13.Cu")
		(net "H_CPU_RMCA_LVC1_R_N")
	)
	(segment
		(start 134.47776 -149.654768)
		(end 125.39472 -149.654768)
		(width 0.127)
		(layer "In13.Cu")
		(net "H_CPU_RMCA_LVC1_R_N")
	)
	(segment
		(start 139.78636 -148.984208)
		(end 139.78636 -150.005288)
		(width 0.127)
		(layer "In13.Cu")
		(net "H_CPU_RMCA_LVC1_R_N")
	)
	(segment
		(start 119.186706 -144.844008)
		(end 118.65102 -145.379694)
		(width 0.127)
		(layer "In13.Cu")
		(net "H_CPU_RMCA_LVC1_R_N")
	)
	(segment
		(start 140.67028 -148.100288)
		(end 139.78636 -148.984208)
		(width 0.127)
		(layer "In13.Cu")
		(net "H_CPU_RMCA_LVC1_R_N")
	)
	(segment
		(start 148.086572 -144.529048)
		(end 143.438626 -144.529048)
		(width 0.127)
		(layer "In13.Cu")
		(net "H_CPU_RMCA_LVC1_R_N")
	)
	(segment
		(start 125.39472 -149.654768)
		(end 120.58396 -144.844008)
		(width 0.127)
		(layer "In13.Cu")
		(net "H_CPU_RMCA_LVC1_R_N")
	)
	(segment
		(start 120.58396 -144.844008)
		(end 119.186706 -144.844008)
		(width 0.127)
		(layer "In13.Cu")
		(net "H_CPU_RMCA_LVC1_R_N")
	)
	(segment
		(start 259.09524 -153.429208)
		(end 258.53644 -153.988008)
		(width 0.127)
		(layer "In13.Cu")
		(net "H_CPU_RMCA_LVC1_R_N")
	)
	(segment
		(start 143.438626 -144.529048)
		(end 140.67028 -147.297394)
		(width 0.127)
		(layer "In13.Cu")
		(net "H_CPU_RMCA_LVC1_R_N")
	)
	(segment
		(start 185.002424 -162.474148)
		(end 171.319444 -148.791168)
		(width 0.127)
		(layer "In13.Cu")
		(net "H_CPU_RMCA_LVC1_R_N")
	)
	(segment
		(start 258.53644 -153.988008)
		(end 216.305892 -153.988008)
		(width 0.127)
		(layer "In13.Cu")
		(net "H_CPU_RMCA_LVC1_R_N")
	)
	(segment
		(start 216.305892 -153.988008)
		(end 207.819752 -162.474148)
		(width 0.127)
		(layer "In13.Cu")
		(net "H_CPU_RMCA_LVC1_R_N")
	)
	(segment
		(start 137.65784 -150.508208)
		(end 136.25068 -149.101048)
		(width 0.127)
		(layer "In13.Cu")
		(net "H_CPU_RMCA_LVC1_R_N")
	)
	(segment
		(start 263.01192 -153.429208)
		(end 259.09524 -153.429208)
		(width 0.127)
		(layer "In13.Cu")
		(net "H_CPU_RMCA_LVC1_R_N")
	)
	(segment
		(start 139.78636 -150.005288)
		(end 139.28344 -150.508208)
		(width 0.127)
		(layer "In13.Cu")
		(net "H_CPU_RMCA_LVC1_R_N")
	)
	(segment
		(start 152.348692 -148.791168)
		(end 148.086572 -144.529048)
		(width 0.127)
		(layer "In13.Cu")
		(net "H_CPU_RMCA_LVC1_R_N")
	)
	(segment
		(start 263.71804 -152.723088)
		(end 263.01192 -153.429208)
		(width 0.127)
		(layer "In13.Cu")
		(net "H_CPU_RMCA_LVC1_R_N")
	)
	(segment
		(start 136.25068 -149.101048)
		(end 135.03148 -149.101048)
		(width 0.127)
		(layer "In13.Cu")
		(net "H_CPU_RMCA_LVC1_R_N")
	)
	(segment
		(start 171.319444 -148.791168)
		(end 152.348692 -148.791168)
		(width 0.127)
		(layer "In13.Cu")
		(net "H_CPU_RMCA_LVC1_R_N")
	)
	(segment
		(start 207.819752 -162.474148)
		(end 185.002424 -162.474148)
		(width 0.127)
		(layer "In13.Cu")
		(net "H_CPU_RMCA_LVC1_R_N")
	)
	(segment
		(start 369.41252 -65.771268)
		(end 370.55552 -65.771268)
		(width 0.12954)
		(layer "F.Cu")
		(net "H_CPU_PREQ_QS_GTL_N")
	)
	(segment
		(start 282.28798 -85.796628)
		(end 300.129448 -85.796628)
		(width 0.12954)
		(layer "F.Cu")
		(net "H_CPU_PREQ_QS_GTL_N")
	)
	(segment
		(start 245.385082 -81.874868)
		(end 252.191012 -81.874868)
		(width 0.12954)
		(layer "F.Cu")
		(net "H_CPU_PREQ_QS_GTL_N")
	)
	(segment
		(start 371.3734 -70.5104)
		(end 368.7953 -67.9323)
		(width 0.12954)
		(layer "F.Cu")
		(net "H_CPU_PREQ_QS_GTL_N")
	)
	(segment
		(start 368.7953 -66.388488)
		(end 369.41252 -65.771268)
		(width 0.12954)
		(layer "F.Cu")
		(net "H_CPU_PREQ_QS_GTL_N")
	)
	(segment
		(start 300.129448 -85.796628)
		(end 304.705512 -90.372692)
		(width 0.12954)
		(layer "F.Cu")
		(net "H_CPU_PREQ_QS_GTL_N")
	)
	(segment
		(start 304.705512 -90.372692)
		(end 357.450136 -90.372692)
		(width 0.12954)
		(layer "F.Cu")
		(net "H_CPU_PREQ_QS_GTL_N")
	)
	(segment
		(start 252.97638 -82.660236)
		(end 279.151588 -82.660236)
		(width 0.12954)
		(layer "F.Cu")
		(net "H_CPU_PREQ_QS_GTL_N")
	)
	(segment
		(start 368.7953 -67.9323)
		(end 368.7953 -66.388488)
		(width 0.12954)
		(layer "F.Cu")
		(net "H_CPU_PREQ_QS_GTL_N")
	)
	(segment
		(start 244.818916 -81.308702)
		(end 245.385082 -81.874868)
		(width 0.12954)
		(layer "F.Cu")
		(net "H_CPU_PREQ_QS_GTL_N")
	)
	(segment
		(start 252.191012 -81.874868)
		(end 252.97638 -82.660236)
		(width 0.12954)
		(layer "F.Cu")
		(net "H_CPU_PREQ_QS_GTL_N")
	)
	(segment
		(start 279.151588 -82.660236)
		(end 282.28798 -85.796628)
		(width 0.12954)
		(layer "F.Cu")
		(net "H_CPU_PREQ_QS_GTL_N")
	)
	(segment
		(start 371.3734 -76.449428)
		(end 371.3734 -70.5104)
		(width 0.12954)
		(layer "F.Cu")
		(net "H_CPU_PREQ_QS_GTL_N")
	)
	(segment
		(start 357.450136 -90.372692)
		(end 371.3734 -76.449428)
		(width 0.12954)
		(layer "F.Cu")
		(net "H_CPU_PREQ_QS_GTL_N")
	)
	(via
		(at 134.993888 -147.2565)
		(size 0.508)
		(drill 0.254)
		(layers "F.Cu" "B.Cu")
		(net "H_CPU_PREQ_QS_GTL_N")
	)
	(via
		(at 256.83464 -151.049228)
		(size 0.508)
		(drill 0.254)
		(layers "F.Cu" "B.Cu")
		(net "H_CPU_PREQ_QS_GTL_N")
	)
	(via
		(at 244.818916 -81.308702)
		(size 0.508)
		(drill 0.254)
		(layers "F.Cu" "B.Cu")
		(net "H_CPU_PREQ_QS_GTL_N")
	)
	(via
		(at 258.11988 -150.078948)
		(size 0.508)
		(drill 0.254)
		(layers "F.Cu" "B.Cu")
		(net "H_CPU_PREQ_QS_GTL_N")
	)
	(segment
		(start 314.16244 -188.125608)
		(end 314.16244 -192.75806)
		(width 0.12954)
		(layer "B.Cu")
		(net "H_CPU_PREQ_QS_GTL_N")
	)
	(segment
		(start 258.11988 -150.078948)
		(end 257.49504 -150.703788)
		(width 0.12954)
		(layer "B.Cu")
		(net "H_CPU_PREQ_QS_GTL_N")
	)
	(segment
		(start 257.50647 -151.532082)
		(end 257.50647 -158.469838)
		(width 0.12954)
		(layer "B.Cu")
		(net "H_CPU_PREQ_QS_GTL_N")
	)
	(segment
		(start 76.463652 -182.05704)
		(end 76.463652 -183.070246)
		(width 0.12954)
		(layer "B.Cu")
		(net "H_CPU_PREQ_QS_GTL_N")
	)
	(segment
		(start 314.16244 -192.75806)
		(end 313.78144 -193.13906)
		(width 0.12954)
		(layer "B.Cu")
		(net "H_CPU_PREQ_QS_GTL_N")
	)
	(segment
		(start 313.419998 -188.35243)
		(end 313.419998 -192.777618)
		(width 0.12954)
		(layer "B.Cu")
		(net "H_CPU_PREQ_QS_GTL_N")
	)
	(segment
		(start 275.33092 -176.294288)
		(end 302.33112 -176.294288)
		(width 0.12954)
		(layer "B.Cu")
		(net "H_CPU_PREQ_QS_GTL_N")
	)
	(segment
		(start 77.481938 -182.05196)
		(end 76.463652 -183.070246)
		(width 0.12954)
		(layer "B.Cu")
		(net "H_CPU_PREQ_QS_GTL_N")
	)
	(segment
		(start 275.1201 -177.035968)
		(end 302.103536 -177.035968)
		(width 0.12954)
		(layer "B.Cu")
		(net "H_CPU_PREQ_QS_GTL_N")
	)
	(segment
		(start 108.538518 -147.2565)
		(end 80.837786 -174.957232)
		(width 0.12954)
		(layer "B.Cu")
		(net "H_CPU_PREQ_QS_GTL_N")
	)
	(segment
		(start 302.103536 -177.035968)
		(end 313.419998 -188.35243)
		(width 0.12954)
		(layer "B.Cu")
		(net "H_CPU_PREQ_QS_GTL_N")
	)
	(segment
		(start 77.481938 -180.439568)
		(end 77.481938 -182.05196)
		(width 0.12954)
		(layer "B.Cu")
		(net "H_CPU_PREQ_QS_GTL_N")
	)
	(segment
		(start 257.50647 -158.469838)
		(end 275.33092 -176.294288)
		(width 0.12954)
		(layer "B.Cu")
		(net "H_CPU_PREQ_QS_GTL_N")
	)
	(segment
		(start 80.837786 -174.957232)
		(end 80.837786 -177.08372)
		(width 0.12954)
		(layer "B.Cu")
		(net "H_CPU_PREQ_QS_GTL_N")
	)
	(segment
		(start 256.83464 -158.750508)
		(end 275.1201 -177.035968)
		(width 0.12954)
		(layer "B.Cu")
		(net "H_CPU_PREQ_QS_GTL_N")
	)
	(segment
		(start 313.419998 -192.777618)
		(end 313.78144 -193.13906)
		(width 0.12954)
		(layer "B.Cu")
		(net "H_CPU_PREQ_QS_GTL_N")
	)
	(segment
		(start 134.993888 -147.2565)
		(end 108.538518 -147.2565)
		(width 0.12954)
		(layer "B.Cu")
		(net "H_CPU_PREQ_QS_GTL_N")
	)
	(segment
		(start 257.49504 -151.520652)
		(end 257.50647 -151.532082)
		(width 0.12954)
		(layer "B.Cu")
		(net "H_CPU_PREQ_QS_GTL_N")
	)
	(segment
		(start 80.837786 -177.08372)
		(end 77.481938 -180.439568)
		(width 0.12954)
		(layer "B.Cu")
		(net "H_CPU_PREQ_QS_GTL_N")
	)
	(segment
		(start 257.49504 -150.703788)
		(end 257.49504 -151.520652)
		(width 0.12954)
		(layer "B.Cu")
		(net "H_CPU_PREQ_QS_GTL_N")
	)
	(segment
		(start 256.83464 -151.049228)
		(end 256.83464 -158.750508)
		(width 0.12954)
		(layer "B.Cu")
		(net "H_CPU_PREQ_QS_GTL_N")
	)
	(segment
		(start 302.33112 -176.294288)
		(end 314.16244 -188.125608)
		(width 0.12954)
		(layer "B.Cu")
		(net "H_CPU_PREQ_QS_GTL_N")
	)
	(segment
		(start 265.19378 -91.557348)
		(end 266.96416 -93.327728)
		(width 0.127)
		(layer "In2.Cu")
		(net "H_CPU_PREQ_QS_GTL_N")
	)
	(segment
		(start 265.91768 -113.237772)
		(end 265.91768 -142.281148)
		(width 0.127)
		(layer "In2.Cu")
		(net "H_CPU_PREQ_QS_GTL_N")
	)
	(segment
		(start 244.818916 -81.308702)
		(end 246.426482 -82.916268)
		(width 0.127)
		(layer "In2.Cu")
		(net "H_CPU_PREQ_QS_GTL_N")
	)
	(segment
		(start 266.96416 -93.327728)
		(end 266.96416 -110.711234)
		(width 0.127)
		(layer "In2.Cu")
		(net "H_CPU_PREQ_QS_GTL_N")
	)
	(segment
		(start 266.96416 -110.711234)
		(end 265.91768 -113.237772)
		(width 0.127)
		(layer "In2.Cu")
		(net "H_CPU_PREQ_QS_GTL_N")
	)
	(segment
		(start 246.79656 -82.916268)
		(end 255.43764 -91.557348)
		(width 0.127)
		(layer "In2.Cu")
		(net "H_CPU_PREQ_QS_GTL_N")
	)
	(segment
		(start 255.43764 -91.557348)
		(end 265.19378 -91.557348)
		(width 0.127)
		(layer "In2.Cu")
		(net "H_CPU_PREQ_QS_GTL_N")
	)
	(segment
		(start 246.426482 -82.916268)
		(end 246.79656 -82.916268)
		(width 0.127)
		(layer "In2.Cu")
		(net "H_CPU_PREQ_QS_GTL_N")
	)
	(segment
		(start 265.91768 -142.281148)
		(end 258.11988 -150.078948)
		(width 0.127)
		(layer "In2.Cu")
		(net "H_CPU_PREQ_QS_GTL_N")
	)
	(segment
		(start 173.19498 -147.310348)
		(end 186.91098 -161.026348)
		(width 0.127)
		(layer "In13.Cu")
		(net "H_CPU_PREQ_QS_GTL_N")
	)
	(segment
		(start 256.83464 -151.181308)
		(end 256.83464 -151.049228)
		(width 0.127)
		(layer "In13.Cu")
		(net "H_CPU_PREQ_QS_GTL_N")
	)
	(segment
		(start 141.37132 -143.081248)
		(end 148.687536 -143.081248)
		(width 0.127)
		(layer "In13.Cu")
		(net "H_CPU_PREQ_QS_GTL_N")
	)
	(segment
		(start 215.705436 -152.540208)
		(end 255.47574 -152.540208)
		(width 0.127)
		(layer "In13.Cu")
		(net "H_CPU_PREQ_QS_GTL_N")
	)
	(segment
		(start 137.196068 -147.2565)
		(end 141.37132 -143.081248)
		(width 0.127)
		(layer "In13.Cu")
		(net "H_CPU_PREQ_QS_GTL_N")
	)
	(segment
		(start 186.91098 -161.026348)
		(end 207.219296 -161.026348)
		(width 0.127)
		(layer "In13.Cu")
		(net "H_CPU_PREQ_QS_GTL_N")
	)
	(segment
		(start 255.47574 -152.540208)
		(end 256.83464 -151.181308)
		(width 0.127)
		(layer "In13.Cu")
		(net "H_CPU_PREQ_QS_GTL_N")
	)
	(segment
		(start 152.916636 -147.310348)
		(end 173.19498 -147.310348)
		(width 0.127)
		(layer "In13.Cu")
		(net "H_CPU_PREQ_QS_GTL_N")
	)
	(segment
		(start 207.219296 -161.026348)
		(end 215.705436 -152.540208)
		(width 0.127)
		(layer "In13.Cu")
		(net "H_CPU_PREQ_QS_GTL_N")
	)
	(segment
		(start 148.687536 -143.081248)
		(end 152.916636 -147.310348)
		(width 0.127)
		(layer "In13.Cu")
		(net "H_CPU_PREQ_QS_GTL_N")
	)
	(segment
		(start 134.993888 -147.2565)
		(end 137.196068 -147.2565)
		(width 0.127)
		(layer "In13.Cu")
		(net "H_CPU_PREQ_QS_GTL_N")
	)
	(segment
		(start 370.84 -70.8152)
		(end 368.43208 -68.40728)
		(width 0.12954)
		(layer "F.Cu")
		(net "H_CPU_PRDY_QS_GTL_N")
	)
	(segment
		(start 282.438602 -85.433408)
		(end 300.28007 -85.433408)
		(width 0.12954)
		(layer "F.Cu")
		(net "H_CPU_PRDY_QS_GTL_N")
	)
	(segment
		(start 368.43208 -68.40728)
		(end 368.43208 -65.250568)
		(width 0.12954)
		(layer "F.Cu")
		(net "H_CPU_PRDY_QS_GTL_N")
	)
	(segment
		(start 304.856134 -90.009472)
		(end 357.299514 -90.009472)
		(width 0.12954)
		(layer "F.Cu")
		(net "H_CPU_PRDY_QS_GTL_N")
	)
	(segment
		(start 300.28007 -85.433408)
		(end 304.856134 -90.009472)
		(width 0.12954)
		(layer "F.Cu")
		(net "H_CPU_PRDY_QS_GTL_N")
	)
	(segment
		(start 253.294134 -82.281776)
		(end 279.28697 -82.281776)
		(width 0.12954)
		(layer "F.Cu")
		(net "H_CPU_PRDY_QS_GTL_N")
	)
	(segment
		(start 279.28697 -82.281776)
		(end 282.438602 -85.433408)
		(width 0.12954)
		(layer "F.Cu")
		(net "H_CPU_PRDY_QS_GTL_N")
	)
	(segment
		(start 252.3109 -81.298542)
		(end 253.294134 -82.281776)
		(width 0.12954)
		(layer "F.Cu")
		(net "H_CPU_PRDY_QS_GTL_N")
	)
	(segment
		(start 245.678706 -81.298542)
		(end 252.3109 -81.298542)
		(width 0.12954)
		(layer "F.Cu")
		(net "H_CPU_PRDY_QS_GTL_N")
	)
	(segment
		(start 368.43208 -65.250568)
		(end 369.861338 -63.82131)
		(width 0.12954)
		(layer "F.Cu")
		(net "H_CPU_PRDY_QS_GTL_N")
	)
	(segment
		(start 370.84 -76.468986)
		(end 370.84 -70.8152)
		(width 0.12954)
		(layer "F.Cu")
		(net "H_CPU_PRDY_QS_GTL_N")
	)
	(segment
		(start 369.861338 -63.82131)
		(end 370.55552 -63.82131)
		(width 0.12954)
		(layer "F.Cu")
		(net "H_CPU_PRDY_QS_GTL_N")
	)
	(segment
		(start 357.299514 -90.009472)
		(end 370.84 -76.468986)
		(width 0.12954)
		(layer "F.Cu")
		(net "H_CPU_PRDY_QS_GTL_N")
	)
	(via
		(at 263.08304 -150.609808)
		(size 0.508)
		(drill 0.254)
		(layers "F.Cu" "B.Cu")
		(net "H_CPU_PRDY_QS_GTL_N")
	)
	(via
		(at 262.44804 -152.723088)
		(size 0.508)
		(drill 0.254)
		(layers "F.Cu" "B.Cu")
		(net "H_CPU_PRDY_QS_GTL_N")
	)
	(via
		(at 185.249312 -148.101304)
		(size 0.508)
		(drill 0.254)
		(layers "F.Cu" "B.Cu")
		(net "H_CPU_PRDY_QS_GTL_N")
	)
	(via
		(at 245.678706 -81.298542)
		(size 0.762)
		(drill 0.254)
		(layers "F.Cu" "B.Cu")
		(net "H_CPU_PRDY_QS_GTL_N")
	)
	(segment
		(start 323.524626 -189.99073)
		(end 323.646292 -189.869064)
		(width 0.12954)
		(layer "B.Cu")
		(net "H_CPU_PRDY_QS_GTL_N")
	)
	(segment
		(start 323.432678 -189.50051)
		(end 323.432678 -189.65545)
		(width 0.12954)
		(layer "B.Cu")
		(net "H_CPU_PRDY_QS_GTL_N")
	)
	(segment
		(start 323.04482 -187.604908)
		(end 323.04482 -189.112652)
		(width 0.12954)
		(layer "B.Cu")
		(net "H_CPU_PRDY_QS_GTL_N")
	)
	(segment
		(start 263.08304 -152.319228)
		(end 263.08304 -154.617928)
		(width 0.12954)
		(layer "B.Cu")
		(net "H_CPU_PRDY_QS_GTL_N")
	)
	(segment
		(start 322.28282 -186.842908)
		(end 323.04482 -187.604908)
		(width 0.12954)
		(layer "B.Cu")
		(net "H_CPU_PRDY_QS_GTL_N")
	)
	(segment
		(start 308.141878 -171.79417)
		(end 321.61988 -185.272172)
		(width 0.12954)
		(layer "B.Cu")
		(net "H_CPU_PRDY_QS_GTL_N")
	)
	(segment
		(start 276.67204 -171.150788)
		(end 308.715664 -171.150788)
		(width 0.12954)
		(layer "B.Cu")
		(net "H_CPU_PRDY_QS_GTL_N")
	)
	(segment
		(start 85.213952 -179.854098)
		(end 84.015072 -181.052978)
		(width 0.12954)
		(layer "B.Cu")
		(net "H_CPU_PRDY_QS_GTL_N")
	)
	(segment
		(start 120.22836 -151.168608)
		(end 110.147862 -151.168608)
		(width 0.12954)
		(layer "B.Cu")
		(net "H_CPU_PRDY_QS_GTL_N")
	)
	(segment
		(start 185.249312 -148.101304)
		(end 185.099706 -147.951698)
		(width 0.12954)
		(layer "B.Cu")
		(net "H_CPU_PRDY_QS_GTL_N")
	)
	(segment
		(start 83.478624 -183.696102)
		(end 84.494624 -183.696102)
		(width 0.12954)
		(layer "B.Cu")
		(net "H_CPU_PRDY_QS_GTL_N")
	)
	(segment
		(start 308.715664 -171.150788)
		(end 322.28282 -184.717944)
		(width 0.12954)
		(layer "B.Cu")
		(net "H_CPU_PRDY_QS_GTL_N")
	)
	(segment
		(start 322.40474 -187.838588)
		(end 322.40474 -189.206632)
		(width 0.12954)
		(layer "B.Cu")
		(net "H_CPU_PRDY_QS_GTL_N")
	)
	(segment
		(start 323.432678 -189.65545)
		(end 323.646292 -189.869064)
		(width 0.12954)
		(layer "B.Cu")
		(net "H_CPU_PRDY_QS_GTL_N")
	)
	(segment
		(start 185.099706 -147.951698)
		(end 182.176166 -147.951698)
		(width 0.12954)
		(layer "B.Cu")
		(net "H_CPU_PRDY_QS_GTL_N")
	)
	(segment
		(start 263.1567 -154.691588)
		(end 263.1567 -157.635448)
		(width 0.12954)
		(layer "B.Cu")
		(net "H_CPU_PRDY_QS_GTL_N")
	)
	(segment
		(start 85.213952 -176.102518)
		(end 85.213952 -179.854098)
		(width 0.12954)
		(layer "B.Cu")
		(net "H_CPU_PRDY_QS_GTL_N")
	)
	(segment
		(start 321.61988 -185.272172)
		(end 321.61988 -187.053728)
		(width 0.12954)
		(layer "B.Cu")
		(net "H_CPU_PRDY_QS_GTL_N")
	)
	(segment
		(start 178.55438 -147.528788)
		(end 174.63643 -151.446738)
		(width 0.12954)
		(layer "B.Cu")
		(net "H_CPU_PRDY_QS_GTL_N")
	)
	(segment
		(start 262.44804 -152.723088)
		(end 262.44804 -157.817058)
		(width 0.12954)
		(layer "B.Cu")
		(net "H_CPU_PRDY_QS_GTL_N")
	)
	(segment
		(start 321.61988 -187.053728)
		(end 322.40474 -187.838588)
		(width 0.12954)
		(layer "B.Cu")
		(net "H_CPU_PRDY_QS_GTL_N")
	)
	(segment
		(start 174.63643 -151.446738)
		(end 134.56285 -151.446738)
		(width 0.12954)
		(layer "B.Cu")
		(net "H_CPU_PRDY_QS_GTL_N")
	)
	(segment
		(start 84.015072 -181.052978)
		(end 84.015072 -183.21655)
		(width 0.12954)
		(layer "B.Cu")
		(net "H_CPU_PRDY_QS_GTL_N")
	)
	(segment
		(start 263.08304 -150.609808)
		(end 262.62584 -151.067008)
		(width 0.12954)
		(layer "B.Cu")
		(net "H_CPU_PRDY_QS_GTL_N")
	)
	(segment
		(start 262.44804 -157.817058)
		(end 276.425152 -171.79417)
		(width 0.12954)
		(layer "B.Cu")
		(net "H_CPU_PRDY_QS_GTL_N")
	)
	(segment
		(start 322.28282 -184.717944)
		(end 322.28282 -186.842908)
		(width 0.12954)
		(layer "B.Cu")
		(net "H_CPU_PRDY_QS_GTL_N")
	)
	(segment
		(start 134.16788 -151.841708)
		(end 120.90146 -151.841708)
		(width 0.12954)
		(layer "B.Cu")
		(net "H_CPU_PRDY_QS_GTL_N")
	)
	(segment
		(start 322.40474 -189.206632)
		(end 323.188838 -189.99073)
		(width 0.12954)
		(layer "B.Cu")
		(net "H_CPU_PRDY_QS_GTL_N")
	)
	(segment
		(start 120.90146 -151.841708)
		(end 120.22836 -151.168608)
		(width 0.12954)
		(layer "B.Cu")
		(net "H_CPU_PRDY_QS_GTL_N")
	)
	(segment
		(start 181.753256 -147.528788)
		(end 178.55438 -147.528788)
		(width 0.12954)
		(layer "B.Cu")
		(net "H_CPU_PRDY_QS_GTL_N")
	)
	(segment
		(start 263.1567 -157.635448)
		(end 276.67204 -171.150788)
		(width 0.12954)
		(layer "B.Cu")
		(net "H_CPU_PRDY_QS_GTL_N")
	)
	(segment
		(start 110.147862 -151.168608)
		(end 85.213952 -176.102518)
		(width 0.12954)
		(layer "B.Cu")
		(net "H_CPU_PRDY_QS_GTL_N")
	)
	(segment
		(start 276.425152 -171.79417)
		(end 308.141878 -171.79417)
		(width 0.12954)
		(layer "B.Cu")
		(net "H_CPU_PRDY_QS_GTL_N")
	)
	(segment
		(start 323.188838 -189.99073)
		(end 323.524626 -189.99073)
		(width 0.12954)
		(layer "B.Cu")
		(net "H_CPU_PRDY_QS_GTL_N")
	)
	(segment
		(start 134.56285 -151.446738)
		(end 134.16788 -151.841708)
		(width 0.12954)
		(layer "B.Cu")
		(net "H_CPU_PRDY_QS_GTL_N")
	)
	(segment
		(start 323.04482 -189.112652)
		(end 323.432678 -189.50051)
		(width 0.12954)
		(layer "B.Cu")
		(net "H_CPU_PRDY_QS_GTL_N")
	)
	(segment
		(start 84.015072 -183.21655)
		(end 84.494624 -183.696102)
		(width 0.12954)
		(layer "B.Cu")
		(net "H_CPU_PRDY_QS_GTL_N")
	)
	(segment
		(start 262.62584 -151.862028)
		(end 263.08304 -152.319228)
		(width 0.12954)
		(layer "B.Cu")
		(net "H_CPU_PRDY_QS_GTL_N")
	)
	(segment
		(start 182.176166 -147.951698)
		(end 181.753256 -147.528788)
		(width 0.12954)
		(layer "B.Cu")
		(net "H_CPU_PRDY_QS_GTL_N")
	)
	(segment
		(start 263.08304 -154.617928)
		(end 263.1567 -154.691588)
		(width 0.12954)
		(layer "B.Cu")
		(net "H_CPU_PRDY_QS_GTL_N")
	)
	(segment
		(start 262.62584 -151.067008)
		(end 262.62584 -151.862028)
		(width 0.12954)
		(layer "B.Cu")
		(net "H_CPU_PRDY_QS_GTL_N")
	)
	(segment
		(start 263.08304 -150.609808)
		(end 263.08304 -145.877788)
		(width 0.127)
		(layer "In2.Cu")
		(net "H_CPU_PRDY_QS_GTL_N")
	)
	(segment
		(start 263.08304 -145.877788)
		(end 266.296648 -142.66418)
		(width 0.127)
		(layer "In2.Cu")
		(net "H_CPU_PRDY_QS_GTL_N")
	)
	(segment
		(start 266.296648 -142.51305)
		(end 266.34948 -142.460218)
		(width 0.127)
		(layer "In2.Cu")
		(net "H_CPU_PRDY_QS_GTL_N")
	)
	(segment
		(start 245.872254 -81.298542)
		(end 245.678706 -81.298542)
		(width 0.127)
		(layer "In2.Cu")
		(net "H_CPU_PRDY_QS_GTL_N")
	)
	(segment
		(start 255.64846 -91.074748)
		(end 245.872254 -81.298542)
		(width 0.127)
		(layer "In2.Cu")
		(net "H_CPU_PRDY_QS_GTL_N")
	)
	(segment
		(start 267.45438 -93.124528)
		(end 265.4046 -91.074748)
		(width 0.127)
		(layer "In2.Cu")
		(net "H_CPU_PRDY_QS_GTL_N")
	)
	(segment
		(start 266.34948 -142.460218)
		(end 266.34948 -113.375948)
		(width 0.127)
		(layer "In2.Cu")
		(net "H_CPU_PRDY_QS_GTL_N")
	)
	(segment
		(start 266.296648 -142.66418)
		(end 266.296648 -142.51305)
		(width 0.127)
		(layer "In2.Cu")
		(net "H_CPU_PRDY_QS_GTL_N")
	)
	(segment
		(start 267.45438 -110.70844)
		(end 267.45438 -93.124528)
		(width 0.127)
		(layer "In2.Cu")
		(net "H_CPU_PRDY_QS_GTL_N")
	)
	(segment
		(start 265.4046 -91.074748)
		(end 255.64846 -91.074748)
		(width 0.127)
		(layer "In2.Cu")
		(net "H_CPU_PRDY_QS_GTL_N")
	)
	(segment
		(start 266.34948 -113.375948)
		(end 267.45438 -110.70844)
		(width 0.127)
		(layer "In2.Cu")
		(net "H_CPU_PRDY_QS_GTL_N")
	)
	(segment
		(start 205.69428 -151.511508)
		(end 206.44104 -152.258268)
		(width 0.127)
		(layer "In13.Cu")
		(net "H_CPU_PRDY_QS_GTL_N")
	)
	(segment
		(start 212.9536 -152.258268)
		(end 215.471756 -149.740112)
		(width 0.127)
		(layer "In13.Cu")
		(net "H_CPU_PRDY_QS_GTL_N")
	)
	(segment
		(start 253.513336 -149.740112)
		(end 254.17018 -149.083268)
		(width 0.127)
		(layer "In13.Cu")
		(net "H_CPU_PRDY_QS_GTL_N")
	)
	(segment
		(start 203.95438 -148.364448)
		(end 203.95438 -149.380448)
		(width 0.127)
		(layer "In13.Cu")
		(net "H_CPU_PRDY_QS_GTL_N")
	)
	(segment
		(start 205.69428 -150.345648)
		(end 205.69428 -151.511508)
		(width 0.127)
		(layer "In13.Cu")
		(net "H_CPU_PRDY_QS_GTL_N")
	)
	(segment
		(start 185.249312 -148.101304)
		(end 185.249312 -147.220686)
		(width 0.127)
		(layer "In13.Cu")
		(net "H_CPU_PRDY_QS_GTL_N")
	)
	(segment
		(start 203.95438 -149.380448)
		(end 204.52588 -149.951948)
		(width 0.127)
		(layer "In13.Cu")
		(net "H_CPU_PRDY_QS_GTL_N")
	)
	(segment
		(start 254.17018 -149.083268)
		(end 260.0452 -149.083268)
		(width 0.127)
		(layer "In13.Cu")
		(net "H_CPU_PRDY_QS_GTL_N")
	)
	(segment
		(start 186.33821 -146.131788)
		(end 201.72172 -146.131788)
		(width 0.127)
		(layer "In13.Cu")
		(net "H_CPU_PRDY_QS_GTL_N")
	)
	(segment
		(start 201.72172 -146.131788)
		(end 203.95438 -148.364448)
		(width 0.127)
		(layer "In13.Cu")
		(net "H_CPU_PRDY_QS_GTL_N")
	)
	(segment
		(start 205.30058 -149.951948)
		(end 205.69428 -150.345648)
		(width 0.127)
		(layer "In13.Cu")
		(net "H_CPU_PRDY_QS_GTL_N")
	)
	(segment
		(start 206.44104 -152.258268)
		(end 212.9536 -152.258268)
		(width 0.127)
		(layer "In13.Cu")
		(net "H_CPU_PRDY_QS_GTL_N")
	)
	(segment
		(start 204.52588 -149.951948)
		(end 205.30058 -149.951948)
		(width 0.127)
		(layer "In13.Cu")
		(net "H_CPU_PRDY_QS_GTL_N")
	)
	(segment
		(start 215.471756 -149.740112)
		(end 253.513336 -149.740112)
		(width 0.127)
		(layer "In13.Cu")
		(net "H_CPU_PRDY_QS_GTL_N")
	)
	(segment
		(start 185.249312 -147.220686)
		(end 186.33821 -146.131788)
		(width 0.127)
		(layer "In13.Cu")
		(net "H_CPU_PRDY_QS_GTL_N")
	)
	(segment
		(start 262.44804 -151.486108)
		(end 262.44804 -152.723088)
		(width 0.127)
		(layer "In13.Cu")
		(net "H_CPU_PRDY_QS_GTL_N")
	)
	(segment
		(start 260.0452 -149.083268)
		(end 262.44804 -151.486108)
		(width 0.127)
		(layer "In13.Cu")
		(net "H_CPU_PRDY_QS_GTL_N")
	)
	(via
		(at 209.22488 -151.094948)
		(size 0.508)
		(drill 0.254)
		(layers "F.Cu" "B.Cu")
		(net "H_CPU_PM_FAST_WAKE_N")
	)
	(via
		(at 153.103072 -192.62979)
		(size 0.508)
		(drill 0.254)
		(layers "F.Cu" "B.Cu")
		(net "H_CPU_PM_FAST_WAKE_N")
	)
	(via
		(at 272.6055 -147.912328)
		(size 0.508)
		(drill 0.254)
		(layers "F.Cu" "B.Cu")
		(net "H_CPU_PM_FAST_WAKE_N")
	)
	(segment
		(start 306.20335 -148.416518)
		(end 307.56352 -149.776688)
		(width 0.12954)
		(layer "B.Cu")
		(net "H_CPU_PM_FAST_WAKE_N")
	)
	(segment
		(start 301.178976 -148.416518)
		(end 306.20335 -148.416518)
		(width 0.12954)
		(layer "B.Cu")
		(net "H_CPU_PM_FAST_WAKE_N")
	)
	(segment
		(start 356.831646 -171.121578)
		(end 361.308142 -175.598074)
		(width 0.12954)
		(layer "B.Cu")
		(net "H_CPU_PM_FAST_WAKE_N")
	)
	(segment
		(start 369.31219 -180.159406)
		(end 369.749324 -180.159406)
		(width 0.12954)
		(layer "B.Cu")
		(net "H_CPU_PM_FAST_WAKE_N")
	)
	(segment
		(start 307.56352 -149.776688)
		(end 322.16217 -149.776688)
		(width 0.12954)
		(layer "B.Cu")
		(net "H_CPU_PM_FAST_WAKE_N")
	)
	(segment
		(start 154.48915 -191.27851)
		(end 154.4955 -191.27216)
		(width 0.12954)
		(layer "B.Cu")
		(net "H_CPU_PM_FAST_WAKE_N")
	)
	(segment
		(start 322.16217 -149.776688)
		(end 328.499216 -152.401524)
		(width 0.12954)
		(layer "B.Cu")
		(net "H_CPU_PM_FAST_WAKE_N")
	)
	(segment
		(start 365.39297 -175.598074)
		(end 369.002818 -179.207922)
		(width 0.12954)
		(layer "B.Cu")
		(net "H_CPU_PM_FAST_WAKE_N")
	)
	(segment
		(start 380.813818 -190.415672)
		(end 380.813818 -189.29096)
		(width 0.12954)
		(layer "B.Cu")
		(net "H_CPU_PM_FAST_WAKE_N")
	)
	(segment
		(start 380.80823 -190.42126)
		(end 380.813818 -190.415672)
		(width 0.12954)
		(layer "B.Cu")
		(net "H_CPU_PM_FAST_WAKE_N")
	)
	(segment
		(start 272.64868 -147.912328)
		(end 273.42338 -147.137628)
		(width 0.12954)
		(layer "B.Cu")
		(net "H_CPU_PM_FAST_WAKE_N")
	)
	(segment
		(start 299.72 -149.189948)
		(end 300.405546 -149.189948)
		(width 0.12954)
		(layer "B.Cu")
		(net "H_CPU_PM_FAST_WAKE_N")
	)
	(segment
		(start 297.66768 -147.137628)
		(end 299.72 -149.189948)
		(width 0.12954)
		(layer "B.Cu")
		(net "H_CPU_PM_FAST_WAKE_N")
	)
	(segment
		(start 154.48915 -192.39357)
		(end 154.48915 -191.27851)
		(width 0.12954)
		(layer "B.Cu")
		(net "H_CPU_PM_FAST_WAKE_N")
	)
	(segment
		(start 369.002818 -179.207922)
		(end 369.002818 -179.850034)
		(width 0.12954)
		(layer "B.Cu")
		(net "H_CPU_PM_FAST_WAKE_N")
	)
	(segment
		(start 300.405546 -149.189948)
		(end 301.178976 -148.416518)
		(width 0.12954)
		(layer "B.Cu")
		(net "H_CPU_PM_FAST_WAKE_N")
	)
	(segment
		(start 379.138688 -188.280802)
		(end 380.148846 -189.29096)
		(width 0.12954)
		(layer "B.Cu")
		(net "H_CPU_PM_FAST_WAKE_N")
	)
	(segment
		(start 361.308142 -175.598074)
		(end 365.39297 -175.598074)
		(width 0.12954)
		(layer "B.Cu")
		(net "H_CPU_PM_FAST_WAKE_N")
	)
	(segment
		(start 154.460702 -191.27216)
		(end 154.4955 -191.27216)
		(width 0.12954)
		(layer "B.Cu")
		(net "H_CPU_PM_FAST_WAKE_N")
	)
	(segment
		(start 380.148846 -189.29096)
		(end 380.813818 -189.29096)
		(width 0.12954)
		(layer "B.Cu")
		(net "H_CPU_PM_FAST_WAKE_N")
	)
	(segment
		(start 328.499216 -152.401524)
		(end 345.287346 -169.189654)
		(width 0.12954)
		(layer "B.Cu")
		(net "H_CPU_PM_FAST_WAKE_N")
	)
	(segment
		(start 345.287346 -169.189654)
		(end 351.635822 -169.189654)
		(width 0.12954)
		(layer "B.Cu")
		(net "H_CPU_PM_FAST_WAKE_N")
	)
	(segment
		(start 369.002818 -179.850034)
		(end 369.31219 -180.159406)
		(width 0.12954)
		(layer "B.Cu")
		(net "H_CPU_PM_FAST_WAKE_N")
	)
	(segment
		(start 273.42338 -147.137628)
		(end 297.66768 -147.137628)
		(width 0.12954)
		(layer "B.Cu")
		(net "H_CPU_PM_FAST_WAKE_N")
	)
	(segment
		(start 374.662446 -179.850542)
		(end 379.138688 -184.326784)
		(width 0.12954)
		(layer "B.Cu")
		(net "H_CPU_PM_FAST_WAKE_N")
	)
	(segment
		(start 272.6055 -147.912328)
		(end 272.64868 -147.912328)
		(width 0.12954)
		(layer "B.Cu")
		(net "H_CPU_PM_FAST_WAKE_N")
	)
	(segment
		(start 369.749324 -180.159406)
		(end 370.058188 -179.850542)
		(width 0.12954)
		(layer "B.Cu")
		(net "H_CPU_PM_FAST_WAKE_N")
	)
	(segment
		(start 370.058188 -179.850542)
		(end 374.662446 -179.850542)
		(width 0.12954)
		(layer "B.Cu")
		(net "H_CPU_PM_FAST_WAKE_N")
	)
	(segment
		(start 351.635822 -169.189654)
		(end 353.567746 -171.121578)
		(width 0.12954)
		(layer "B.Cu")
		(net "H_CPU_PM_FAST_WAKE_N")
	)
	(segment
		(start 379.138688 -184.326784)
		(end 379.138688 -188.280802)
		(width 0.12954)
		(layer "B.Cu")
		(net "H_CPU_PM_FAST_WAKE_N")
	)
	(segment
		(start 153.103072 -192.62979)
		(end 154.460702 -191.27216)
		(width 0.12954)
		(layer "B.Cu")
		(net "H_CPU_PM_FAST_WAKE_N")
	)
	(segment
		(start 353.567746 -171.121578)
		(end 356.831646 -171.121578)
		(width 0.12954)
		(layer "B.Cu")
		(net "H_CPU_PM_FAST_WAKE_N")
	)
	(segment
		(start 176.11852 -193.385948)
		(end 175.78578 -193.718688)
		(width 0.127)
		(layer "In2.Cu")
		(net "H_CPU_PM_FAST_WAKE_N")
	)
	(segment
		(start 202.50912 -187.411868)
		(end 202.50912 -189.510924)
		(width 0.127)
		(layer "In2.Cu")
		(net "H_CPU_PM_FAST_WAKE_N")
	)
	(segment
		(start 202.50912 -189.510924)
		(end 200.948036 -191.072008)
		(width 0.127)
		(layer "In2.Cu")
		(net "H_CPU_PM_FAST_WAKE_N")
	)
	(segment
		(start 209.22488 -151.094948)
		(end 209.22488 -164.029136)
		(width 0.127)
		(layer "In2.Cu")
		(net "H_CPU_PM_FAST_WAKE_N")
	)
	(segment
		(start 153.44013 -192.966848)
		(end 153.103072 -192.62979)
		(width 0.127)
		(layer "In2.Cu")
		(net "H_CPU_PM_FAST_WAKE_N")
	)
	(segment
		(start 209.22488 -164.029136)
		(end 208.90738 -164.346636)
		(width 0.127)
		(layer "In2.Cu")
		(net "H_CPU_PM_FAST_WAKE_N")
	)
	(segment
		(start 158.31566 -192.966848)
		(end 153.44013 -192.966848)
		(width 0.127)
		(layer "In2.Cu")
		(net "H_CPU_PM_FAST_WAKE_N")
	)
	(segment
		(start 200.948036 -191.072008)
		(end 196.40042 -191.072008)
		(width 0.127)
		(layer "In2.Cu")
		(net "H_CPU_PM_FAST_WAKE_N")
	)
	(segment
		(start 194.08648 -193.385948)
		(end 176.11852 -193.385948)
		(width 0.127)
		(layer "In2.Cu")
		(net "H_CPU_PM_FAST_WAKE_N")
	)
	(segment
		(start 208.90738 -164.346636)
		(end 208.90738 -181.013608)
		(width 0.127)
		(layer "In2.Cu")
		(net "H_CPU_PM_FAST_WAKE_N")
	)
	(segment
		(start 208.90738 -181.013608)
		(end 202.50912 -187.411868)
		(width 0.127)
		(layer "In2.Cu")
		(net "H_CPU_PM_FAST_WAKE_N")
	)
	(segment
		(start 159.0675 -193.718688)
		(end 158.31566 -192.966848)
		(width 0.127)
		(layer "In2.Cu")
		(net "H_CPU_PM_FAST_WAKE_N")
	)
	(segment
		(start 175.78578 -193.718688)
		(end 159.0675 -193.718688)
		(width 0.127)
		(layer "In2.Cu")
		(net "H_CPU_PM_FAST_WAKE_N")
	)
	(segment
		(start 196.40042 -191.072008)
		(end 194.08648 -193.385948)
		(width 0.127)
		(layer "In2.Cu")
		(net "H_CPU_PM_FAST_WAKE_N")
	)
	(segment
		(start 270.05788 -149.570948)
		(end 267.54836 -149.570948)
		(width 0.127)
		(layer "In13.Cu")
		(net "H_CPU_PM_FAST_WAKE_N")
	)
	(segment
		(start 211.1248 -150.084028)
		(end 210.39582 -150.813008)
		(width 0.127)
		(layer "In13.Cu")
		(net "H_CPU_PM_FAST_WAKE_N")
	)
	(segment
		(start 213.22284 -150.084028)
		(end 211.1248 -150.084028)
		(width 0.127)
		(layer "In13.Cu")
		(net "H_CPU_PM_FAST_WAKE_N")
	)
	(segment
		(start 253.31166 -148.143468)
		(end 252.609858 -148.84527)
		(width 0.127)
		(layer "In13.Cu")
		(net "H_CPU_PM_FAST_WAKE_N")
	)
	(segment
		(start 209.50682 -150.813008)
		(end 209.22488 -151.094948)
		(width 0.127)
		(layer "In13.Cu")
		(net "H_CPU_PM_FAST_WAKE_N")
	)
	(segment
		(start 210.39582 -150.813008)
		(end 209.50682 -150.813008)
		(width 0.127)
		(layer "In13.Cu")
		(net "H_CPU_PM_FAST_WAKE_N")
	)
	(segment
		(start 214.461598 -148.84527)
		(end 213.22284 -150.084028)
		(width 0.127)
		(layer "In13.Cu")
		(net "H_CPU_PM_FAST_WAKE_N")
	)
	(segment
		(start 272.6055 -147.912328)
		(end 271.7165 -147.912328)
		(width 0.127)
		(layer "In13.Cu")
		(net "H_CPU_PM_FAST_WAKE_N")
	)
	(segment
		(start 271.7165 -147.912328)
		(end 270.05788 -149.570948)
		(width 0.127)
		(layer "In13.Cu")
		(net "H_CPU_PM_FAST_WAKE_N")
	)
	(segment
		(start 267.54836 -149.570948)
		(end 266.12088 -148.143468)
		(width 0.127)
		(layer "In13.Cu")
		(net "H_CPU_PM_FAST_WAKE_N")
	)
	(segment
		(start 266.12088 -148.143468)
		(end 253.31166 -148.143468)
		(width 0.127)
		(layer "In13.Cu")
		(net "H_CPU_PM_FAST_WAKE_N")
	)
	(segment
		(start 252.609858 -148.84527)
		(end 214.461598 -148.84527)
		(width 0.127)
		(layer "In13.Cu")
		(net "H_CPU_PM_FAST_WAKE_N")
	)
	(segment
		(start 186.30392 -102.463854)
		(end 187.499244 -101.26853)
		(width 0.12954)
		(layer "F.Cu")
		(net "H_CPU_NMI_LVC1_R_N")
	)
	(segment
		(start 187.499244 -101.26853)
		(end 187.50788 -101.259894)
		(width 0.12954)
		(layer "F.Cu")
		(net "H_CPU_NMI_LVC1_R_N")
	)
	(segment
		(start 187.50788 -101.259894)
		(end 187.50788 -100.059998)
		(width 0.12954)
		(layer "F.Cu")
		(net "H_CPU_NMI_LVC1_R_N")
	)
	(segment
		(start 186.155584 -104.975406)
		(end 186.30392 -104.82707)
		(width 0.12954)
		(layer "F.Cu")
		(net "H_CPU_NMI_LVC1_R_N")
	)
	(segment
		(start 186.30392 -104.82707)
		(end 186.30392 -102.463854)
		(width 0.12954)
		(layer "F.Cu")
		(net "H_CPU_NMI_LVC1_R_N")
	)
	(via
		(at 187.499244 -101.26853)
		(size 0.762)
		(drill 0.381)
		(layers "F.Cu" "B.Cu")
		(net "H_CPU_NMI_LVC1_R_N")
	)
	(segment
		(start 204.757782 -152.161748)
		(end 201.160126 -155.759404)
		(width 0.12954)
		(layer "F.Cu")
		(net "H_CPU_NMI_LVC1_N")
	)
	(segment
		(start 201.160126 -155.759404)
		(end 201.160126 -157.069536)
		(width 0.12954)
		(layer "F.Cu")
		(net "H_CPU_NMI_LVC1_N")
	)
	(segment
		(start 260.770116 -151.422608)
		(end 260.770116 -151.485092)
		(width 0.12954)
		(layer "F.Cu")
		(net "H_CPU_NMI_LVC1_N")
	)
	(segment
		(start 260.09346 -152.161748)
		(end 204.757782 -152.161748)
		(width 0.12954)
		(layer "F.Cu")
		(net "H_CPU_NMI_LVC1_N")
	)
	(segment
		(start 260.770116 -151.485092)
		(end 260.09346 -152.161748)
		(width 0.12954)
		(layer "F.Cu")
		(net "H_CPU_NMI_LVC1_N")
	)
	(segment
		(start 187.50788 -99.259898)
		(end 187.50788 -98.643948)
		(width 0.12954)
		(layer "F.Cu")
		(net "H_CPU_NMI_LVC1_N")
	)
	(via
		(at 136.303004 -149.987)
		(size 0.508)
		(drill 0.254)
		(layers "F.Cu" "B.Cu")
		(net "H_CPU_NMI_LVC1_N")
	)
	(via
		(at 269.225522 -110.569756)
		(size 0.508)
		(drill 0.254)
		(layers "F.Cu" "B.Cu")
		(net "H_CPU_NMI_LVC1_N")
	)
	(via
		(at 260.770116 -151.422608)
		(size 0.508)
		(drill 0.254)
		(layers "F.Cu" "B.Cu")
		(net "H_CPU_NMI_LVC1_N")
	)
	(via
		(at 187.50788 -98.643948)
		(size 0.508)
		(drill 0.254)
		(layers "F.Cu" "B.Cu")
		(net "H_CPU_NMI_LVC1_N")
	)
	(via
		(at 201.160126 -157.069536)
		(size 0.508)
		(drill 0.254)
		(layers "F.Cu" "B.Cu")
		(net "H_CPU_NMI_LVC1_N")
	)
	(segment
		(start 81.447132 -180.33746)
		(end 81.446878 -180.33746)
		(width 0.12954)
		(layer "B.Cu")
		(net "H_CPU_NMI_LVC1_N")
	)
	(segment
		(start 81.44637 -180.336952)
		(end 81.446624 -180.336952)
		(width 0.12954)
		(layer "B.Cu")
		(net "H_CPU_NMI_LVC1_N")
	)
	(segment
		(start 81.446878 -180.33746)
		(end 81.446624 -180.337206)
		(width 0.12954)
		(layer "B.Cu")
		(net "H_CPU_NMI_LVC1_N")
	)
	(segment
		(start 136.303004 -149.987)
		(end 109.669834 -149.987)
		(width 0.12954)
		(layer "B.Cu")
		(net "H_CPU_NMI_LVC1_N")
	)
	(segment
		(start 109.669834 -149.987)
		(end 83.625436 -176.031398)
		(width 0.12954)
		(layer "B.Cu")
		(net "H_CPU_NMI_LVC1_N")
	)
	(segment
		(start 81.446624 -180.337206)
		(end 81.446624 -183.696102)
		(width 0.12954)
		(layer "B.Cu")
		(net "H_CPU_NMI_LVC1_N")
	)
	(segment
		(start 83.625436 -178.157886)
		(end 81.44637 -180.336952)
		(width 0.12954)
		(layer "B.Cu")
		(net "H_CPU_NMI_LVC1_N")
	)
	(segment
		(start 260.770116 -157.799024)
		(end 276.002242 -173.03115)
		(width 0.12954)
		(layer "B.Cu")
		(net "H_CPU_NMI_LVC1_N")
	)
	(segment
		(start 83.625436 -176.031398)
		(end 83.625436 -178.157886)
		(width 0.12954)
		(layer "B.Cu")
		(net "H_CPU_NMI_LVC1_N")
	)
	(segment
		(start 276.002242 -173.03115)
		(end 306.73421 -173.03115)
		(width 0.12954)
		(layer "B.Cu")
		(net "H_CPU_NMI_LVC1_N")
	)
	(segment
		(start 81.446624 -180.336952)
		(end 81.447132 -180.33746)
		(width 0.12954)
		(layer "B.Cu")
		(net "H_CPU_NMI_LVC1_N")
	)
	(segment
		(start 306.73421 -173.03115)
		(end 319.073022 -185.369962)
		(width 0.12954)
		(layer "B.Cu")
		(net "H_CPU_NMI_LVC1_N")
	)
	(segment
		(start 319.073022 -185.369962)
		(end 319.073022 -185.56986)
		(width 0.12954)
		(layer "B.Cu")
		(net "H_CPU_NMI_LVC1_N")
	)
	(segment
		(start 260.770116 -151.422608)
		(end 260.770116 -157.799024)
		(width 0.12954)
		(layer "B.Cu")
		(net "H_CPU_NMI_LVC1_N")
	)
	(segment
		(start 269.225522 -120.348248)
		(end 269.225522 -110.569756)
		(width 0.127)
		(layer "In2.Cu")
		(net "H_CPU_NMI_LVC1_N")
	)
	(segment
		(start 269.21968 -120.35409)
		(end 269.225522 -120.348248)
		(width 0.127)
		(layer "In2.Cu")
		(net "H_CPU_NMI_LVC1_N")
	)
	(segment
		(start 267.2842 -150.586948)
		(end 268.819122 -150.586948)
		(width 0.127)
		(layer "In2.Cu")
		(net "H_CPU_NMI_LVC1_N")
	)
	(segment
		(start 271.185386 -138.59256)
		(end 269.21968 -136.626854)
		(width 0.127)
		(layer "In2.Cu")
		(net "H_CPU_NMI_LVC1_N")
	)
	(segment
		(start 265.837924 -152.033224)
		(end 267.2842 -150.586948)
		(width 0.127)
		(layer "In2.Cu")
		(net "H_CPU_NMI_LVC1_N")
	)
	(segment
		(start 271.185386 -148.220684)
		(end 271.185386 -138.59256)
		(width 0.127)
		(layer "In2.Cu")
		(net "H_CPU_NMI_LVC1_N")
	)
	(segment
		(start 260.777736 -151.430228)
		(end 262.203184 -151.430228)
		(width 0.127)
		(layer "In2.Cu")
		(net "H_CPU_NMI_LVC1_N")
	)
	(segment
		(start 262.80618 -152.033224)
		(end 265.837924 -152.033224)
		(width 0.127)
		(layer "In2.Cu")
		(net "H_CPU_NMI_LVC1_N")
	)
	(segment
		(start 262.203184 -151.430228)
		(end 262.80618 -152.033224)
		(width 0.127)
		(layer "In2.Cu")
		(net "H_CPU_NMI_LVC1_N")
	)
	(segment
		(start 260.770116 -151.422608)
		(end 260.777736 -151.430228)
		(width 0.127)
		(layer "In2.Cu")
		(net "H_CPU_NMI_LVC1_N")
	)
	(segment
		(start 269.21968 -136.626854)
		(end 269.21968 -120.35409)
		(width 0.127)
		(layer "In2.Cu")
		(net "H_CPU_NMI_LVC1_N")
	)
	(segment
		(start 268.819122 -150.586948)
		(end 271.185386 -148.220684)
		(width 0.127)
		(layer "In2.Cu")
		(net "H_CPU_NMI_LVC1_N")
	)
	(segment
		(start 263.689592 -112.098836)
		(end 263.000236 -112.788192)
		(width 0.127)
		(layer "In15.Cu")
		(net "H_CPU_NMI_LVC1_N")
	)
	(segment
		(start 245.401592 -93.5101)
		(end 236.377226 -93.5101)
		(width 0.127)
		(layer "In15.Cu")
		(net "H_CPU_NMI_LVC1_N")
	)
	(segment
		(start 235.626148 -94.261178)
		(end 217.801952 -94.261178)
		(width 0.127)
		(layer "In15.Cu")
		(net "H_CPU_NMI_LVC1_N")
	)
	(segment
		(start 188.31306 -150.642828)
		(end 182.81777 -150.642828)
		(width 0.127)
		(layer "In15.Cu")
		(net "H_CPU_NMI_LVC1_N")
	)
	(segment
		(start 208.435194 -96.6851)
		(end 195.16344 -96.6851)
		(width 0.127)
		(layer "In15.Cu")
		(net "H_CPU_NMI_LVC1_N")
	)
	(segment
		(start 209.270346 -95.849948)
		(end 208.435194 -96.6851)
		(width 0.127)
		(layer "In15.Cu")
		(net "H_CPU_NMI_LVC1_N")
	)
	(segment
		(start 248.547128 -99.649026)
		(end 248.547128 -98.658172)
		(width 0.127)
		(layer "In15.Cu")
		(net "H_CPU_NMI_LVC1_N")
	)
	(segment
		(start 264.79881 -112.098836)
		(end 263.689592 -112.098836)
		(width 0.127)
		(layer "In15.Cu")
		(net "H_CPU_NMI_LVC1_N")
	)
	(segment
		(start 247.577864 -107.877102)
		(end 247.577864 -100.61829)
		(width 0.127)
		(layer "In15.Cu")
		(net "H_CPU_NMI_LVC1_N")
	)
	(segment
		(start 136.756902 -149.987)
		(end 136.303004 -149.987)
		(width 0.127)
		(layer "In15.Cu")
		(net "H_CPU_NMI_LVC1_N")
	)
	(segment
		(start 247.62714 -95.735648)
		(end 245.401592 -93.5101)
		(width 0.127)
		(layer "In15.Cu")
		(net "H_CPU_NMI_LVC1_N")
	)
	(segment
		(start 137.650728 -149.093174)
		(end 136.756902 -149.987)
		(width 0.127)
		(layer "In15.Cu")
		(net "H_CPU_NMI_LVC1_N")
	)
	(segment
		(start 200.847706 -156.757116)
		(end 200.847706 -151.484076)
		(width 0.127)
		(layer "In15.Cu")
		(net "H_CPU_NMI_LVC1_N")
	)
	(segment
		(start 217.801952 -94.261178)
		(end 216.213182 -95.849948)
		(width 0.127)
		(layer "In15.Cu")
		(net "H_CPU_NMI_LVC1_N")
	)
	(segment
		(start 197.110604 -147.746974)
		(end 191.208914 -147.746974)
		(width 0.127)
		(layer "In15.Cu")
		(net "H_CPU_NMI_LVC1_N")
	)
	(segment
		(start 268.773402 -111.021876)
		(end 265.87577 -111.021876)
		(width 0.127)
		(layer "In15.Cu")
		(net "H_CPU_NMI_LVC1_N")
	)
	(segment
		(start 269.225522 -110.569756)
		(end 268.773402 -111.021876)
		(width 0.127)
		(layer "In15.Cu")
		(net "H_CPU_NMI_LVC1_N")
	)
	(segment
		(start 248.547128 -98.658172)
		(end 247.62714 -97.738184)
		(width 0.127)
		(layer "In15.Cu")
		(net "H_CPU_NMI_LVC1_N")
	)
	(segment
		(start 263.000236 -112.788192)
		(end 252.488954 -112.788192)
		(width 0.127)
		(layer "In15.Cu")
		(net "H_CPU_NMI_LVC1_N")
	)
	(segment
		(start 247.577864 -100.61829)
		(end 248.547128 -99.649026)
		(width 0.127)
		(layer "In15.Cu")
		(net "H_CPU_NMI_LVC1_N")
	)
	(segment
		(start 181.268116 -149.093174)
		(end 137.650728 -149.093174)
		(width 0.127)
		(layer "In15.Cu")
		(net "H_CPU_NMI_LVC1_N")
	)
	(segment
		(start 236.377226 -93.5101)
		(end 235.626148 -94.261178)
		(width 0.127)
		(layer "In15.Cu")
		(net "H_CPU_NMI_LVC1_N")
	)
	(segment
		(start 193.204592 -98.643948)
		(end 187.50788 -98.643948)
		(width 0.127)
		(layer "In15.Cu")
		(net "H_CPU_NMI_LVC1_N")
	)
	(segment
		(start 216.213182 -95.849948)
		(end 209.270346 -95.849948)
		(width 0.127)
		(layer "In15.Cu")
		(net "H_CPU_NMI_LVC1_N")
	)
	(segment
		(start 265.87577 -111.021876)
		(end 264.79881 -112.098836)
		(width 0.127)
		(layer "In15.Cu")
		(net "H_CPU_NMI_LVC1_N")
	)
	(segment
		(start 182.81777 -150.642828)
		(end 181.268116 -149.093174)
		(width 0.127)
		(layer "In15.Cu")
		(net "H_CPU_NMI_LVC1_N")
	)
	(segment
		(start 200.847706 -151.484076)
		(end 197.110604 -147.746974)
		(width 0.127)
		(layer "In15.Cu")
		(net "H_CPU_NMI_LVC1_N")
	)
	(segment
		(start 201.160126 -157.069536)
		(end 200.847706 -156.757116)
		(width 0.127)
		(layer "In15.Cu")
		(net "H_CPU_NMI_LVC1_N")
	)
	(segment
		(start 195.16344 -96.6851)
		(end 193.204592 -98.643948)
		(width 0.127)
		(layer "In15.Cu")
		(net "H_CPU_NMI_LVC1_N")
	)
	(segment
		(start 191.208914 -147.746974)
		(end 188.31306 -150.642828)
		(width 0.127)
		(layer "In15.Cu")
		(net "H_CPU_NMI_LVC1_N")
	)
	(segment
		(start 247.62714 -97.738184)
		(end 247.62714 -95.735648)
		(width 0.127)
		(layer "In15.Cu")
		(net "H_CPU_NMI_LVC1_N")
	)
	(segment
		(start 252.488954 -112.788192)
		(end 247.577864 -107.877102)
		(width 0.127)
		(layer "In15.Cu")
		(net "H_CPU_NMI_LVC1_N")
	)
	(segment
		(start 147.442936 -92.222828)
		(end 146.959828 -92.222828)
		(width 0.12954)
		(layer "F.Cu")
		(net "H_CPU_ERR2_PCH_R_N")
	)
	(segment
		(start 148.956268 -93.73616)
		(end 147.442936 -92.222828)
		(width 0.12954)
		(layer "F.Cu")
		(net "H_CPU_ERR2_PCH_R_N")
	)
	(segment
		(start 146.74088 -95.959168)
		(end 148.956268 -93.74378)
		(width 0.12954)
		(layer "F.Cu")
		(net "H_CPU_ERR2_PCH_R_N")
	)
	(segment
		(start 328.626978 -54.558946)
		(end 329.165966 -54.558946)
		(width 0.12954)
		(layer "F.Cu")
		(net "H_CPU_ERR2_PCH_R_N")
	)
	(segment
		(start 146.74088 -96.992948)
		(end 146.74088 -95.959168)
		(width 0.12954)
		(layer "F.Cu")
		(net "H_CPU_ERR2_PCH_R_N")
	)
	(segment
		(start 148.956268 -93.74378)
		(end 148.956268 -93.73616)
		(width 0.12954)
		(layer "F.Cu")
		(net "H_CPU_ERR2_PCH_R_N")
	)
	(via
		(at 328.626978 -54.558946)
		(size 0.4572)
		(drill 0.2032)
		(layers "F.Cu" "B.Cu")
		(net "H_CPU_ERR2_PCH_R_N")
	)
	(via
		(at 314.12688 -65.369948)
		(size 0.508)
		(drill 0.254)
		(layers "F.Cu" "B.Cu")
		(net "H_CPU_ERR2_PCH_R_N")
	)
	(via
		(at 312.04408 -51.349148)
		(size 0.508)
		(drill 0.254)
		(layers "F.Cu" "B.Cu")
		(net "H_CPU_ERR2_PCH_R_N")
	)
	(via
		(at 146.74088 -96.992948)
		(size 0.508)
		(drill 0.254)
		(layers "F.Cu" "B.Cu")
		(net "H_CPU_ERR2_PCH_R_N")
	)
	(via
		(at 318.19088 -49.113948)
		(size 0.6604)
		(drill 0.3302)
		(layers "F.Cu" "B.Cu")
		(net "H_CPU_ERR2_PCH_R_N")
	)
	(segment
		(start 324.666864 -52.614068)
		(end 323.009006 -52.614068)
		(width 0.12954)
		(layer "B.Cu")
		(net "H_CPU_ERR2_PCH_R_N")
	)
	(segment
		(start 326.762618 -54.13883)
		(end 326.083676 -53.459888)
		(width 0.12954)
		(layer "B.Cu")
		(net "H_CPU_ERR2_PCH_R_N")
	)
	(segment
		(start 325.512684 -53.459888)
		(end 324.666864 -52.614068)
		(width 0.12954)
		(layer "B.Cu")
		(net "H_CPU_ERR2_PCH_R_N")
	)
	(segment
		(start 312.664856 -50.728372)
		(end 313.081162 -50.645568)
		(width 0.12954)
		(layer "B.Cu")
		(net "H_CPU_ERR2_PCH_R_N")
	)
	(segment
		(start 323.009006 -52.614068)
		(end 322.211446 -51.816508)
		(width 0.12954)
		(layer "B.Cu")
		(net "H_CPU_ERR2_PCH_R_N")
	)
	(segment
		(start 314.35802 -50.645568)
		(end 315.54293 -49.460658)
		(width 0.12954)
		(layer "B.Cu")
		(net "H_CPU_ERR2_PCH_R_N")
	)
	(segment
		(start 315.54293 -49.460658)
		(end 315.54293 -49.113948)
		(width 0.12954)
		(layer "B.Cu")
		(net "H_CPU_ERR2_PCH_R_N")
	)
	(segment
		(start 320.89344 -51.816508)
		(end 318.19088 -49.113948)
		(width 0.12954)
		(layer "B.Cu")
		(net "H_CPU_ERR2_PCH_R_N")
	)
	(segment
		(start 313.081162 -50.645568)
		(end 314.35802 -50.645568)
		(width 0.12954)
		(layer "B.Cu")
		(net "H_CPU_ERR2_PCH_R_N")
	)
	(segment
		(start 328.626978 -54.558946)
		(end 328.342498 -54.558946)
		(width 0.12954)
		(layer "B.Cu")
		(net "H_CPU_ERR2_PCH_R_N")
	)
	(segment
		(start 328.342498 -54.558946)
		(end 327.922382 -54.13883)
		(width 0.12954)
		(layer "B.Cu")
		(net "H_CPU_ERR2_PCH_R_N")
	)
	(segment
		(start 322.211446 -51.816508)
		(end 320.89344 -51.816508)
		(width 0.12954)
		(layer "B.Cu")
		(net "H_CPU_ERR2_PCH_R_N")
	)
	(segment
		(start 326.083676 -53.459888)
		(end 325.512684 -53.459888)
		(width 0.12954)
		(layer "B.Cu")
		(net "H_CPU_ERR2_PCH_R_N")
	)
	(segment
		(start 318.19088 -49.113948)
		(end 315.54293 -49.113948)
		(width 0.12954)
		(layer "B.Cu")
		(net "H_CPU_ERR2_PCH_R_N")
	)
	(segment
		(start 327.922382 -54.13883)
		(end 326.762618 -54.13883)
		(width 0.12954)
		(layer "B.Cu")
		(net "H_CPU_ERR2_PCH_R_N")
	)
	(segment
		(start 312.04408 -51.349148)
		(end 312.664856 -50.728372)
		(width 0.12954)
		(layer "B.Cu")
		(net "H_CPU_ERR2_PCH_R_N")
	)
	(segment
		(start 312.13044 -51.349148)
		(end 312.04408 -51.349148)
		(width 0.127)
		(layer "In2.Cu")
		(net "H_CPU_ERR2_PCH_R_N")
	)
	(segment
		(start 312.3438 -51.562508)
		(end 312.13044 -51.349148)
		(width 0.127)
		(layer "In2.Cu")
		(net "H_CPU_ERR2_PCH_R_N")
	)
	(segment
		(start 314.12688 -65.369948)
		(end 315.58738 -63.909448)
		(width 0.127)
		(layer "In2.Cu")
		(net "H_CPU_ERR2_PCH_R_N")
	)
	(segment
		(start 312.3438 -55.987188)
		(end 312.3438 -51.562508)
		(width 0.127)
		(layer "In2.Cu")
		(net "H_CPU_ERR2_PCH_R_N")
	)
	(segment
		(start 315.58738 -63.909448)
		(end 315.58738 -59.230768)
		(width 0.127)
		(layer "In2.Cu")
		(net "H_CPU_ERR2_PCH_R_N")
	)
	(segment
		(start 315.58738 -59.230768)
		(end 312.3438 -55.987188)
		(width 0.127)
		(layer "In2.Cu")
		(net "H_CPU_ERR2_PCH_R_N")
	)
	(segment
		(start 206.9846 -92.1512)
		(end 206.5274 -92.6084)
		(width 0.127)
		(layer "In11.Cu")
		(net "H_CPU_ERR2_PCH_R_N")
	)
	(segment
		(start 195.5292 -92.6084)
		(end 195.072 -92.1512)
		(width 0.127)
		(layer "In11.Cu")
		(net "H_CPU_ERR2_PCH_R_N")
	)
	(segment
		(start 240.00714 -72.862948)
		(end 232.41762 -72.862948)
		(width 0.127)
		(layer "In11.Cu")
		(net "H_CPU_ERR2_PCH_R_N")
	)
	(segment
		(start 304.42408 -66.60388)
		(end 304.42408 -76.415392)
		(width 0.127)
		(layer "In11.Cu")
		(net "H_CPU_ERR2_PCH_R_N")
	)
	(segment
		(start 206.5274 -92.6084)
		(end 195.5292 -92.6084)
		(width 0.127)
		(layer "In11.Cu")
		(net "H_CPU_ERR2_PCH_R_N")
	)
	(segment
		(start 298.207938 -82.631534)
		(end 249.775726 -82.631534)
		(width 0.127)
		(layer "In11.Cu")
		(net "H_CPU_ERR2_PCH_R_N")
	)
	(segment
		(start 207.975708 -92.1512)
		(end 206.9846 -92.1512)
		(width 0.127)
		(layer "In11.Cu")
		(net "H_CPU_ERR2_PCH_R_N")
	)
	(segment
		(start 304.42408 -76.415392)
		(end 298.207938 -82.631534)
		(width 0.127)
		(layer "In11.Cu")
		(net "H_CPU_ERR2_PCH_R_N")
	)
	(segment
		(start 249.775726 -82.631534)
		(end 240.00714 -72.862948)
		(width 0.127)
		(layer "In11.Cu")
		(net "H_CPU_ERR2_PCH_R_N")
	)
	(segment
		(start 313.61888 -65.877948)
		(end 305.150012 -65.877948)
		(width 0.127)
		(layer "In11.Cu")
		(net "H_CPU_ERR2_PCH_R_N")
	)
	(segment
		(start 232.41762 -72.862948)
		(end 215.467438 -89.81313)
		(width 0.127)
		(layer "In11.Cu")
		(net "H_CPU_ERR2_PCH_R_N")
	)
	(segment
		(start 305.150012 -65.877948)
		(end 304.42408 -66.60388)
		(width 0.127)
		(layer "In11.Cu")
		(net "H_CPU_ERR2_PCH_R_N")
	)
	(segment
		(start 146.80438 -96.929448)
		(end 146.74088 -96.992948)
		(width 0.127)
		(layer "In11.Cu")
		(net "H_CPU_ERR2_PCH_R_N")
	)
	(segment
		(start 164.86759 -93.090238)
		(end 161.02838 -96.929448)
		(width 0.127)
		(layer "In11.Cu")
		(net "H_CPU_ERR2_PCH_R_N")
	)
	(segment
		(start 161.02838 -96.929448)
		(end 146.80438 -96.929448)
		(width 0.127)
		(layer "In11.Cu")
		(net "H_CPU_ERR2_PCH_R_N")
	)
	(segment
		(start 188.021722 -88.682322)
		(end 171.185332 -88.682322)
		(width 0.127)
		(layer "In11.Cu")
		(net "H_CPU_ERR2_PCH_R_N")
	)
	(segment
		(start 171.185332 -88.682322)
		(end 166.777416 -93.090238)
		(width 0.127)
		(layer "In11.Cu")
		(net "H_CPU_ERR2_PCH_R_N")
	)
	(segment
		(start 314.12688 -65.369948)
		(end 313.61888 -65.877948)
		(width 0.127)
		(layer "In11.Cu")
		(net "H_CPU_ERR2_PCH_R_N")
	)
	(segment
		(start 210.313778 -89.81313)
		(end 207.975708 -92.1512)
		(width 0.127)
		(layer "In11.Cu")
		(net "H_CPU_ERR2_PCH_R_N")
	)
	(segment
		(start 191.4906 -92.1512)
		(end 188.021722 -88.682322)
		(width 0.127)
		(layer "In11.Cu")
		(net "H_CPU_ERR2_PCH_R_N")
	)
	(segment
		(start 195.072 -92.1512)
		(end 191.4906 -92.1512)
		(width 0.127)
		(layer "In11.Cu")
		(net "H_CPU_ERR2_PCH_R_N")
	)
	(segment
		(start 215.467438 -89.81313)
		(end 210.313778 -89.81313)
		(width 0.127)
		(layer "In11.Cu")
		(net "H_CPU_ERR2_PCH_R_N")
	)
	(segment
		(start 166.777416 -93.090238)
		(end 164.86759 -93.090238)
		(width 0.127)
		(layer "In11.Cu")
		(net "H_CPU_ERR2_PCH_R_N")
	)
	(segment
		(start 142.7988 -106.530648)
		(end 143.3322 -105.997248)
		(width 0.12954)
		(layer "F.Cu")
		(net "H_CPU_ERR2_LVC1_R_N")
	)
	(segment
		(start 143.3322 -105.997248)
		(end 143.3322 -104.516428)
		(width 0.12954)
		(layer "F.Cu")
		(net "H_CPU_ERR2_LVC1_R_N")
	)
	(via
		(at 141.58722 -148.227288)
		(size 0.508)
		(drill 0.254)
		(layers "F.Cu" "B.Cu")
		(net "H_CPU_ERR2_LVC1_R_N")
	)
	(via
		(at 259.500116 -154.000708)
		(size 0.508)
		(drill 0.254)
		(layers "F.Cu" "B.Cu")
		(net "H_CPU_ERR2_LVC1_R_N")
	)
	(via
		(at 142.7988 -106.530648)
		(size 0.508)
		(drill 0.254)
		(layers "F.Cu" "B.Cu")
		(net "H_CPU_ERR2_LVC1_R_N")
	)
	(segment
		(start 275.515578 -174.20463)
		(end 302.914558 -174.20463)
		(width 0.12954)
		(layer "B.Cu")
		(net "H_CPU_ERR2_LVC1_R_N")
	)
	(segment
		(start 259.500116 -158.189168)
		(end 275.515578 -174.20463)
		(width 0.12954)
		(layer "B.Cu")
		(net "H_CPU_ERR2_LVC1_R_N")
	)
	(segment
		(start 316.75324 -191.61379)
		(end 317.158878 -192.019428)
		(width 0.12954)
		(layer "B.Cu")
		(net "H_CPU_ERR2_LVC1_R_N")
	)
	(segment
		(start 140.147548 -148.81352)
		(end 109.183678 -148.81352)
		(width 0.12954)
		(layer "B.Cu")
		(net "H_CPU_ERR2_LVC1_R_N")
	)
	(segment
		(start 302.914558 -174.20463)
		(end 316.75324 -188.043312)
		(width 0.12954)
		(layer "B.Cu")
		(net "H_CPU_ERR2_LVC1_R_N")
	)
	(segment
		(start 109.183678 -148.81352)
		(end 82.451956 -175.545242)
		(width 0.12954)
		(layer "B.Cu")
		(net "H_CPU_ERR2_LVC1_R_N")
	)
	(segment
		(start 141.58722 -148.227288)
		(end 140.73378 -148.227288)
		(width 0.12954)
		(layer "B.Cu")
		(net "H_CPU_ERR2_LVC1_R_N")
	)
	(segment
		(start 79.790798 -180.332888)
		(end 79.790798 -183.319928)
		(width 0.12954)
		(layer "B.Cu")
		(net "H_CPU_ERR2_LVC1_R_N")
	)
	(segment
		(start 82.451956 -177.67173)
		(end 79.790798 -180.332888)
		(width 0.12954)
		(layer "B.Cu")
		(net "H_CPU_ERR2_LVC1_R_N")
	)
	(segment
		(start 317.56604 -192.30848)
		(end 317.276988 -192.019428)
		(width 0.12954)
		(layer "B.Cu")
		(net "H_CPU_ERR2_LVC1_R_N")
	)
	(segment
		(start 316.75324 -188.043312)
		(end 316.75324 -191.61379)
		(width 0.12954)
		(layer "B.Cu")
		(net "H_CPU_ERR2_LVC1_R_N")
	)
	(segment
		(start 79.790798 -183.319928)
		(end 79.414624 -183.696102)
		(width 0.12954)
		(layer "B.Cu")
		(net "H_CPU_ERR2_LVC1_R_N")
	)
	(segment
		(start 140.73378 -148.227288)
		(end 140.147548 -148.81352)
		(width 0.12954)
		(layer "B.Cu")
		(net "H_CPU_ERR2_LVC1_R_N")
	)
	(segment
		(start 317.56604 -193.13906)
		(end 317.56604 -192.30848)
		(width 0.12954)
		(layer "B.Cu")
		(net "H_CPU_ERR2_LVC1_R_N")
	)
	(segment
		(start 259.500116 -154.000708)
		(end 259.500116 -158.189168)
		(width 0.12954)
		(layer "B.Cu")
		(net "H_CPU_ERR2_LVC1_R_N")
	)
	(segment
		(start 82.451956 -175.545242)
		(end 82.451956 -177.67173)
		(width 0.12954)
		(layer "B.Cu")
		(net "H_CPU_ERR2_LVC1_R_N")
	)
	(segment
		(start 317.158878 -192.019428)
		(end 317.276988 -192.019428)
		(width 0.12954)
		(layer "B.Cu")
		(net "H_CPU_ERR2_LVC1_R_N")
	)
	(segment
		(start 142.5575 -108.295948)
		(end 142.5575 -106.771948)
		(width 0.127)
		(layer "In2.Cu")
		(net "H_CPU_ERR2_LVC1_R_N")
	)
	(segment
		(start 141.58722 -148.227288)
		(end 140.46708 -147.107148)
		(width 0.127)
		(layer "In2.Cu")
		(net "H_CPU_ERR2_LVC1_R_N")
	)
	(segment
		(start 142.5575 -106.771948)
		(end 142.7988 -106.530648)
		(width 0.127)
		(layer "In2.Cu")
		(net "H_CPU_ERR2_LVC1_R_N")
	)
	(segment
		(start 140.46708 -110.386368)
		(end 142.5575 -108.295948)
		(width 0.127)
		(layer "In2.Cu")
		(net "H_CPU_ERR2_LVC1_R_N")
	)
	(segment
		(start 140.46708 -147.107148)
		(end 140.46708 -110.386368)
		(width 0.127)
		(layer "In2.Cu")
		(net "H_CPU_ERR2_LVC1_R_N")
	)
	(segment
		(start 152.137872 -149.299168)
		(end 147.875752 -145.037048)
		(width 0.127)
		(layer "In13.Cu")
		(net "H_CPU_ERR2_LVC1_R_N")
	)
	(segment
		(start 141.58722 -147.119848)
		(end 141.58722 -148.227288)
		(width 0.127)
		(layer "In13.Cu")
		(net "H_CPU_ERR2_LVC1_R_N")
	)
	(segment
		(start 171.108878 -149.299168)
		(end 152.137872 -149.299168)
		(width 0.127)
		(layer "In13.Cu")
		(net "H_CPU_ERR2_LVC1_R_N")
	)
	(segment
		(start 208.030318 -162.982148)
		(end 184.791858 -162.982148)
		(width 0.127)
		(layer "In13.Cu")
		(net "H_CPU_ERR2_LVC1_R_N")
	)
	(segment
		(start 259.500116 -154.000708)
		(end 259.40258 -154.000708)
		(width 0.127)
		(layer "In13.Cu")
		(net "H_CPU_ERR2_LVC1_R_N")
	)
	(segment
		(start 216.516458 -154.496008)
		(end 208.030318 -162.982148)
		(width 0.127)
		(layer "In13.Cu")
		(net "H_CPU_ERR2_LVC1_R_N")
	)
	(segment
		(start 259.40258 -154.000708)
		(end 258.90728 -154.496008)
		(width 0.127)
		(layer "In13.Cu")
		(net "H_CPU_ERR2_LVC1_R_N")
	)
	(segment
		(start 143.67002 -145.037048)
		(end 141.58722 -147.119848)
		(width 0.127)
		(layer "In13.Cu")
		(net "H_CPU_ERR2_LVC1_R_N")
	)
	(segment
		(start 258.90728 -154.496008)
		(end 216.516458 -154.496008)
		(width 0.127)
		(layer "In13.Cu")
		(net "H_CPU_ERR2_LVC1_R_N")
	)
	(segment
		(start 184.791858 -162.982148)
		(end 171.108878 -149.299168)
		(width 0.127)
		(layer "In13.Cu")
		(net "H_CPU_ERR2_LVC1_R_N")
	)
	(segment
		(start 147.875752 -145.037048)
		(end 143.67002 -145.037048)
		(width 0.127)
		(layer "In13.Cu")
		(net "H_CPU_ERR2_LVC1_R_N")
	)
	(segment
		(start 143.3322 -103.716328)
		(end 143.3322 -102.516178)
		(width 0.12954)
		(layer "F.Cu")
		(net "H_CPU_ERR2_LVC1_N")
	)
	(segment
		(start 142.30604 -101.490018)
		(end 142.30604 -100.729542)
		(width 0.12954)
		(layer "F.Cu")
		(net "H_CPU_ERR2_LVC1_N")
	)
	(segment
		(start 143.29918 -102.483158)
		(end 142.30604 -101.490018)
		(width 0.12954)
		(layer "F.Cu")
		(net "H_CPU_ERR2_LVC1_N")
	)
	(segment
		(start 143.3322 -102.516178)
		(end 143.29918 -102.483158)
		(width 0.12954)
		(layer "F.Cu")
		(net "H_CPU_ERR2_LVC1_N")
	)
	(via
		(at 143.29918 -102.483158)
		(size 0.762)
		(drill 0.381)
		(layers "F.Cu" "B.Cu")
		(net "H_CPU_ERR2_LVC1_N")
	)
	(segment
		(start 149.44598 -88.966548)
		(end 148.3868 -87.907368)
		(width 0.12954)
		(layer "F.Cu")
		(net "H_CPU_ERR1_PCH_R_N")
	)
	(segment
		(start 143.433292 -89.078816)
		(end 143.433292 -92.234258)
		(width 0.12954)
		(layer "F.Cu")
		(net "H_CPU_ERR1_PCH_R_N")
	)
	(segment
		(start 328.626978 -56.438546)
		(end 329.165966 -56.438546)
		(width 0.12954)
		(layer "F.Cu")
		(net "H_CPU_ERR1_PCH_R_N")
	)
	(segment
		(start 148.3868 -87.907368)
		(end 144.60474 -87.907368)
		(width 0.12954)
		(layer "F.Cu")
		(net "H_CPU_ERR1_PCH_R_N")
	)
	(segment
		(start 146.0627 -97.434908)
		(end 146.594576 -97.966784)
		(width 0.12954)
		(layer "F.Cu")
		(net "H_CPU_ERR1_PCH_R_N")
	)
	(segment
		(start 147.969732 -97.966784)
		(end 149.44598 -96.490536)
		(width 0.12954)
		(layer "F.Cu")
		(net "H_CPU_ERR1_PCH_R_N")
	)
	(segment
		(start 146.594576 -97.966784)
		(end 147.969732 -97.966784)
		(width 0.12954)
		(layer "F.Cu")
		(net "H_CPU_ERR1_PCH_R_N")
	)
	(segment
		(start 149.44598 -96.490536)
		(end 149.44598 -88.966548)
		(width 0.12954)
		(layer "F.Cu")
		(net "H_CPU_ERR1_PCH_R_N")
	)
	(segment
		(start 144.60474 -87.907368)
		(end 143.433292 -89.078816)
		(width 0.12954)
		(layer "F.Cu")
		(net "H_CPU_ERR1_PCH_R_N")
	)
	(via
		(at 319.04178 -58.296048)
		(size 0.508)
		(drill 0.254)
		(layers "F.Cu" "B.Cu")
		(net "H_CPU_ERR1_PCH_R_N")
	)
	(via
		(at 324.548246 -58.641234)
		(size 0.6604)
		(drill 0.3302)
		(layers "F.Cu" "B.Cu")
		(net "H_CPU_ERR1_PCH_R_N")
	)
	(via
		(at 146.0627 -97.434908)
		(size 0.762)
		(drill 0.254)
		(layers "F.Cu" "B.Cu")
		(net "H_CPU_ERR1_PCH_R_N")
	)
	(via
		(at 328.626978 -56.438546)
		(size 0.4572)
		(drill 0.2032)
		(layers "F.Cu" "B.Cu")
		(net "H_CPU_ERR1_PCH_R_N")
	)
	(segment
		(start 325.742046 -58.279284)
		(end 327.283318 -56.738012)
		(width 0.12954)
		(layer "B.Cu")
		(net "H_CPU_ERR1_PCH_R_N")
	)
	(segment
		(start 327.283318 -56.738012)
		(end 328.327512 -56.738012)
		(width 0.12954)
		(layer "B.Cu")
		(net "H_CPU_ERR1_PCH_R_N")
	)
	(segment
		(start 319.44437 -58.698638)
		(end 320.178176 -58.698638)
		(width 0.12954)
		(layer "B.Cu")
		(net "H_CPU_ERR1_PCH_R_N")
	)
	(segment
		(start 320.809366 -58.698638)
		(end 321.117976 -59.007248)
		(width 0.12954)
		(layer "B.Cu")
		(net "H_CPU_ERR1_PCH_R_N")
	)
	(segment
		(start 328.327512 -56.738012)
		(end 328.626978 -56.438546)
		(width 0.12954)
		(layer "B.Cu")
		(net "H_CPU_ERR1_PCH_R_N")
	)
	(segment
		(start 324.169786 -58.641234)
		(end 324.548246 -58.641234)
		(width 0.12954)
		(layer "B.Cu")
		(net "H_CPU_ERR1_PCH_R_N")
	)
	(segment
		(start 321.117976 -59.007248)
		(end 323.803772 -59.007248)
		(width 0.12954)
		(layer "B.Cu")
		(net "H_CPU_ERR1_PCH_R_N")
	)
	(segment
		(start 324.548246 -58.641234)
		(end 324.910196 -58.279284)
		(width 0.12954)
		(layer "B.Cu")
		(net "H_CPU_ERR1_PCH_R_N")
	)
	(segment
		(start 323.803772 -59.007248)
		(end 324.169786 -58.641234)
		(width 0.12954)
		(layer "B.Cu")
		(net "H_CPU_ERR1_PCH_R_N")
	)
	(segment
		(start 324.910196 -58.279284)
		(end 325.742046 -58.279284)
		(width 0.12954)
		(layer "B.Cu")
		(net "H_CPU_ERR1_PCH_R_N")
	)
	(segment
		(start 319.04178 -58.296048)
		(end 319.44437 -58.698638)
		(width 0.12954)
		(layer "B.Cu")
		(net "H_CPU_ERR1_PCH_R_N")
	)
	(segment
		(start 320.178176 -58.698638)
		(end 320.809366 -58.698638)
		(width 0.12954)
		(layer "B.Cu")
		(net "H_CPU_ERR1_PCH_R_N")
	)
	(segment
		(start 188.303408 -88.202008)
		(end 169.037254 -88.202008)
		(width 0.127)
		(layer "In11.Cu")
		(net "H_CPU_ERR1_PCH_R_N")
	)
	(segment
		(start 191.607948 -91.506548)
		(end 188.303408 -88.202008)
		(width 0.127)
		(layer "In11.Cu")
		(net "H_CPU_ERR1_PCH_R_N")
	)
	(segment
		(start 317.86068 -58.006488)
		(end 317.30188 -58.565288)
		(width 0.127)
		(layer "In11.Cu")
		(net "H_CPU_ERR1_PCH_R_N")
	)
	(segment
		(start 169.037254 -88.202008)
		(end 160.754314 -96.484948)
		(width 0.127)
		(layer "In11.Cu")
		(net "H_CPU_ERR1_PCH_R_N")
	)
	(segment
		(start 146.0627 -96.919288)
		(end 146.0627 -97.434908)
		(width 0.127)
		(layer "In11.Cu")
		(net "H_CPU_ERR1_PCH_R_N")
	)
	(segment
		(start 208.885282 -89.326466)
		(end 206.085948 -92.1258)
		(width 0.127)
		(layer "In11.Cu")
		(net "H_CPU_ERR1_PCH_R_N")
	)
	(segment
		(start 317.30188 -58.565288)
		(end 317.30188 -61.885322)
		(width 0.127)
		(layer "In11.Cu")
		(net "H_CPU_ERR1_PCH_R_N")
	)
	(segment
		(start 195.834 -92.1258)
		(end 195.214748 -91.506548)
		(width 0.127)
		(layer "In11.Cu")
		(net "H_CPU_ERR1_PCH_R_N")
	)
	(segment
		(start 304.939446 -65.369948)
		(end 303.99228 -66.317114)
		(width 0.127)
		(layer "In11.Cu")
		(net "H_CPU_ERR1_PCH_R_N")
	)
	(segment
		(start 232.23855 -72.431148)
		(end 215.343232 -89.326466)
		(width 0.127)
		(layer "In11.Cu")
		(net "H_CPU_ERR1_PCH_R_N")
	)
	(segment
		(start 195.214748 -91.506548)
		(end 191.607948 -91.506548)
		(width 0.127)
		(layer "In11.Cu")
		(net "H_CPU_ERR1_PCH_R_N")
	)
	(segment
		(start 313.436254 -65.369948)
		(end 304.939446 -65.369948)
		(width 0.127)
		(layer "In11.Cu")
		(net "H_CPU_ERR1_PCH_R_N")
	)
	(segment
		(start 146.49704 -96.484948)
		(end 146.0627 -96.919288)
		(width 0.127)
		(layer "In11.Cu")
		(net "H_CPU_ERR1_PCH_R_N")
	)
	(segment
		(start 303.99228 -76.236322)
		(end 298.028868 -82.199734)
		(width 0.127)
		(layer "In11.Cu")
		(net "H_CPU_ERR1_PCH_R_N")
	)
	(segment
		(start 315.2775 -63.909702)
		(end 314.8965 -63.909702)
		(width 0.127)
		(layer "In11.Cu")
		(net "H_CPU_ERR1_PCH_R_N")
	)
	(segment
		(start 314.8965 -63.909702)
		(end 313.436254 -65.369948)
		(width 0.127)
		(layer "In11.Cu")
		(net "H_CPU_ERR1_PCH_R_N")
	)
	(segment
		(start 318.75222 -58.006488)
		(end 317.86068 -58.006488)
		(width 0.127)
		(layer "In11.Cu")
		(net "H_CPU_ERR1_PCH_R_N")
	)
	(segment
		(start 206.085948 -92.1258)
		(end 195.834 -92.1258)
		(width 0.127)
		(layer "In11.Cu")
		(net "H_CPU_ERR1_PCH_R_N")
	)
	(segment
		(start 298.028868 -82.199734)
		(end 249.954796 -82.199734)
		(width 0.127)
		(layer "In11.Cu")
		(net "H_CPU_ERR1_PCH_R_N")
	)
	(segment
		(start 317.30188 -61.885322)
		(end 315.2775 -63.909702)
		(width 0.127)
		(layer "In11.Cu")
		(net "H_CPU_ERR1_PCH_R_N")
	)
	(segment
		(start 160.754314 -96.484948)
		(end 146.49704 -96.484948)
		(width 0.127)
		(layer "In11.Cu")
		(net "H_CPU_ERR1_PCH_R_N")
	)
	(segment
		(start 319.04178 -58.296048)
		(end 318.75222 -58.006488)
		(width 0.127)
		(layer "In11.Cu")
		(net "H_CPU_ERR1_PCH_R_N")
	)
	(segment
		(start 215.343232 -89.326466)
		(end 208.885282 -89.326466)
		(width 0.127)
		(layer "In11.Cu")
		(net "H_CPU_ERR1_PCH_R_N")
	)
	(segment
		(start 303.99228 -66.317114)
		(end 303.99228 -76.236322)
		(width 0.127)
		(layer "In11.Cu")
		(net "H_CPU_ERR1_PCH_R_N")
	)
	(segment
		(start 249.954796 -82.199734)
		(end 240.18621 -72.431148)
		(width 0.127)
		(layer "In11.Cu")
		(net "H_CPU_ERR1_PCH_R_N")
	)
	(segment
		(start 240.18621 -72.431148)
		(end 232.23855 -72.431148)
		(width 0.127)
		(layer "In11.Cu")
		(net "H_CPU_ERR1_PCH_R_N")
	)
	(segment
		(start 140.7922 -105.476548)
		(end 140.7922 -104.516428)
		(width 0.12954)
		(layer "F.Cu")
		(net "H_CPU_ERR1_LVC1_R_N")
	)
	(segment
		(start 139.61618 -106.652568)
		(end 140.7922 -105.476548)
		(width 0.12954)
		(layer "F.Cu")
		(net "H_CPU_ERR1_LVC1_R_N")
	)
	(via
		(at 78.955138 -181.89067)
		(size 0.6604)
		(drill 0.3302)
		(layers "F.Cu" "B.Cu")
		(net "H_CPU_ERR1_LVC1_R_N")
	)
	(via
		(at 258.826 -152.664668)
		(size 0.508)
		(drill 0.254)
		(layers "F.Cu" "B.Cu")
		(net "H_CPU_ERR1_LVC1_R_N")
	)
	(via
		(at 139.61618 -106.652568)
		(size 0.508)
		(drill 0.254)
		(layers "F.Cu" "B.Cu")
		(net "H_CPU_ERR1_LVC1_R_N")
	)
	(via
		(at 139.78128 -148.173948)
		(size 0.508)
		(drill 0.254)
		(layers "F.Cu" "B.Cu")
		(net "H_CPU_ERR1_LVC1_R_N")
	)
	(segment
		(start 78.955138 -180.626258)
		(end 78.955138 -181.89067)
		(width 0.12954)
		(layer "B.Cu")
		(net "H_CPU_ERR1_LVC1_R_N")
	)
	(segment
		(start 315.9252 -190.815468)
		(end 315.569092 -190.815468)
		(width 0.12954)
		(layer "B.Cu")
		(net "H_CPU_ERR1_LVC1_R_N")
	)
	(segment
		(start 78.955138 -180.626004)
		(end 78.955392 -180.626004)
		(width 0.12954)
		(layer "B.Cu")
		(net "H_CPU_ERR1_LVC1_R_N")
	)
	(segment
		(start 275.625814 -174.85741)
		(end 302.691038 -174.85741)
		(width 0.12954)
		(layer "B.Cu")
		(net "H_CPU_ERR1_LVC1_R_N")
	)
	(segment
		(start 316.30874 -192.89776)
		(end 316.30874 -191.199008)
		(width 0.12954)
		(layer "B.Cu")
		(net "H_CPU_ERR1_LVC1_R_N")
	)
	(segment
		(start 82.068416 -177.512726)
		(end 78.955138 -180.626004)
		(width 0.12954)
		(layer "B.Cu")
		(net "H_CPU_ERR1_LVC1_R_N")
	)
	(segment
		(start 78.955138 -182.978806)
		(end 78.223618 -183.710326)
		(width 0.12954)
		(layer "B.Cu")
		(net "H_CPU_ERR1_LVC1_R_N")
	)
	(segment
		(start 258.826 -158.057596)
		(end 275.625814 -174.85741)
		(width 0.12954)
		(layer "B.Cu")
		(net "H_CPU_ERR1_LVC1_R_N")
	)
	(segment
		(start 137.676128 -148.42998)
		(end 109.024674 -148.42998)
		(width 0.12954)
		(layer "B.Cu")
		(net "H_CPU_ERR1_LVC1_R_N")
	)
	(segment
		(start 78.955646 -180.626258)
		(end 78.955138 -180.626258)
		(width 0.12954)
		(layer "B.Cu")
		(net "H_CPU_ERR1_LVC1_R_N")
	)
	(segment
		(start 302.691038 -174.85741)
		(end 315.569092 -187.735464)
		(width 0.12954)
		(layer "B.Cu")
		(net "H_CPU_ERR1_LVC1_R_N")
	)
	(segment
		(start 137.93216 -148.173948)
		(end 137.676128 -148.42998)
		(width 0.12954)
		(layer "B.Cu")
		(net "H_CPU_ERR1_LVC1_R_N")
	)
	(segment
		(start 78.955138 -181.89067)
		(end 78.955138 -182.978806)
		(width 0.12954)
		(layer "B.Cu")
		(net "H_CPU_ERR1_LVC1_R_N")
	)
	(segment
		(start 139.78128 -148.173948)
		(end 137.93216 -148.173948)
		(width 0.12954)
		(layer "B.Cu")
		(net "H_CPU_ERR1_LVC1_R_N")
	)
	(segment
		(start 109.024674 -148.42998)
		(end 82.068416 -175.386238)
		(width 0.12954)
		(layer "B.Cu")
		(net "H_CPU_ERR1_LVC1_R_N")
	)
	(segment
		(start 78.955392 -180.626004)
		(end 78.955646 -180.626258)
		(width 0.12954)
		(layer "B.Cu")
		(net "H_CPU_ERR1_LVC1_R_N")
	)
	(segment
		(start 315.569092 -187.735464)
		(end 315.569092 -190.815468)
		(width 0.12954)
		(layer "B.Cu")
		(net "H_CPU_ERR1_LVC1_R_N")
	)
	(segment
		(start 316.30874 -191.199008)
		(end 315.9252 -190.815468)
		(width 0.12954)
		(layer "B.Cu")
		(net "H_CPU_ERR1_LVC1_R_N")
	)
	(segment
		(start 258.826 -152.664668)
		(end 258.826 -158.057596)
		(width 0.12954)
		(layer "B.Cu")
		(net "H_CPU_ERR1_LVC1_R_N")
	)
	(segment
		(start 82.068416 -175.386238)
		(end 82.068416 -177.512726)
		(width 0.12954)
		(layer "B.Cu")
		(net "H_CPU_ERR1_LVC1_R_N")
	)
	(segment
		(start 316.55004 -193.13906)
		(end 316.30874 -192.89776)
		(width 0.12954)
		(layer "B.Cu")
		(net "H_CPU_ERR1_LVC1_R_N")
	)
	(segment
		(start 139.93368 -148.021548)
		(end 139.93368 -106.970068)
		(width 0.127)
		(layer "In2.Cu")
		(net "H_CPU_ERR1_LVC1_R_N")
	)
	(segment
		(start 139.93368 -106.970068)
		(end 139.61618 -106.652568)
		(width 0.127)
		(layer "In2.Cu")
		(net "H_CPU_ERR1_LVC1_R_N")
	)
	(segment
		(start 139.78128 -148.173948)
		(end 139.93368 -148.021548)
		(width 0.127)
		(layer "In2.Cu")
		(net "H_CPU_ERR1_LVC1_R_N")
	)
	(segment
		(start 139.78128 -148.173948)
		(end 139.78128 -147.391628)
		(width 0.127)
		(layer "In13.Cu")
		(net "H_CPU_ERR1_LVC1_R_N")
	)
	(segment
		(start 172.66031 -148.283168)
		(end 186.34329 -161.966148)
		(width 0.127)
		(layer "In13.Cu")
		(net "H_CPU_ERR1_LVC1_R_N")
	)
	(segment
		(start 207.609186 -161.966148)
		(end 216.095326 -153.480008)
		(width 0.127)
		(layer "In13.Cu")
		(net "H_CPU_ERR1_LVC1_R_N")
	)
	(segment
		(start 152.559512 -148.283168)
		(end 172.66031 -148.283168)
		(width 0.127)
		(layer "In13.Cu")
		(net "H_CPU_ERR1_LVC1_R_N")
	)
	(segment
		(start 186.34329 -161.966148)
		(end 207.609186 -161.966148)
		(width 0.127)
		(layer "In13.Cu")
		(net "H_CPU_ERR1_LVC1_R_N")
	)
	(segment
		(start 143.15186 -144.021048)
		(end 148.297392 -144.021048)
		(width 0.127)
		(layer "In13.Cu")
		(net "H_CPU_ERR1_LVC1_R_N")
	)
	(segment
		(start 258.01066 -153.480008)
		(end 258.826 -152.664668)
		(width 0.127)
		(layer "In13.Cu")
		(net "H_CPU_ERR1_LVC1_R_N")
	)
	(segment
		(start 139.78128 -147.391628)
		(end 143.15186 -144.021048)
		(width 0.127)
		(layer "In13.Cu")
		(net "H_CPU_ERR1_LVC1_R_N")
	)
	(segment
		(start 148.297392 -144.021048)
		(end 152.559512 -148.283168)
		(width 0.127)
		(layer "In13.Cu")
		(net "H_CPU_ERR1_LVC1_R_N")
	)
	(segment
		(start 216.095326 -153.480008)
		(end 258.01066 -153.480008)
		(width 0.127)
		(layer "In13.Cu")
		(net "H_CPU_ERR1_LVC1_R_N")
	)
	(segment
		(start 140.51534 -103.439468)
		(end 140.7922 -103.716328)
		(width 0.12954)
		(layer "F.Cu")
		(net "H_CPU_ERR1_LVC1_N")
	)
	(segment
		(start 140.51534 -102.527608)
		(end 140.51534 -103.439468)
		(width 0.12954)
		(layer "F.Cu")
		(net "H_CPU_ERR1_LVC1_N")
	)
	(segment
		(start 140.51534 -102.039928)
		(end 140.51534 -102.527608)
		(width 0.12954)
		(layer "F.Cu")
		(net "H_CPU_ERR1_LVC1_N")
	)
	(segment
		(start 141.006068 -100.729542)
		(end 141.006068 -101.5492)
		(width 0.12954)
		(layer "F.Cu")
		(net "H_CPU_ERR1_LVC1_N")
	)
	(segment
		(start 141.006068 -101.5492)
		(end 140.51534 -102.039928)
		(width 0.12954)
		(layer "F.Cu")
		(net "H_CPU_ERR1_LVC1_N")
	)
	(via
		(at 140.51534 -102.527608)
		(size 0.762)
		(drill 0.381)
		(layers "F.Cu" "B.Cu")
		(net "H_CPU_ERR1_LVC1_N")
	)
	(segment
		(start 150.97252 -95.62846)
		(end 150.97252 -92.291916)
		(width 0.12954)
		(layer "F.Cu")
		(net "H_CPU_ERR0_PCH_R_N")
	)
	(segment
		(start 145.696432 -98.41484)
		(end 148.18614 -98.41484)
		(width 0.12954)
		(layer "F.Cu")
		(net "H_CPU_ERR0_PCH_R_N")
	)
	(segment
		(start 328.626978 -55.498746)
		(end 329.165966 -55.498746)
		(width 0.12954)
		(layer "F.Cu")
		(net "H_CPU_ERR0_PCH_R_N")
	)
	(segment
		(start 148.18614 -98.41484)
		(end 150.97252 -95.62846)
		(width 0.12954)
		(layer "F.Cu")
		(net "H_CPU_ERR0_PCH_R_N")
	)
	(segment
		(start 145.21688 -96.992948)
		(end 145.21688 -97.935288)
		(width 0.12954)
		(layer "F.Cu")
		(net "H_CPU_ERR0_PCH_R_N")
	)
	(segment
		(start 145.21688 -97.935288)
		(end 145.696432 -98.41484)
		(width 0.12954)
		(layer "F.Cu")
		(net "H_CPU_ERR0_PCH_R_N")
	)
	(via
		(at 145.21688 -96.992948)
		(size 0.508)
		(drill 0.254)
		(layers "F.Cu" "B.Cu")
		(net "H_CPU_ERR0_PCH_R_N")
	)
	(via
		(at 316.15888 -58.511948)
		(size 0.508)
		(drill 0.254)
		(layers "F.Cu" "B.Cu")
		(net "H_CPU_ERR0_PCH_R_N")
	)
	(via
		(at 328.626978 -55.498746)
		(size 0.4572)
		(drill 0.2032)
		(layers "F.Cu" "B.Cu")
		(net "H_CPU_ERR0_PCH_R_N")
	)
	(via
		(at 327.593706 -55.498746)
		(size 0.6604)
		(drill 0.3302)
		(layers "F.Cu" "B.Cu")
		(net "H_CPU_ERR0_PCH_R_N")
	)
	(segment
		(start 324.125082 -54.422548)
		(end 324.648576 -54.422548)
		(width 0.12954)
		(layer "B.Cu")
		(net "H_CPU_ERR0_PCH_R_N")
	)
	(segment
		(start 323.462142 -55.085488)
		(end 324.125082 -54.422548)
		(width 0.12954)
		(layer "B.Cu")
		(net "H_CPU_ERR0_PCH_R_N")
	)
	(segment
		(start 325.724774 -55.498746)
		(end 327.593706 -55.498746)
		(width 0.12954)
		(layer "B.Cu")
		(net "H_CPU_ERR0_PCH_R_N")
	)
	(segment
		(start 320.996564 -56.211978)
		(end 322.123054 -55.085488)
		(width 0.12954)
		(layer "B.Cu")
		(net "H_CPU_ERR0_PCH_R_N")
	)
	(segment
		(start 322.123054 -55.085488)
		(end 323.462142 -55.085488)
		(width 0.12954)
		(layer "B.Cu")
		(net "H_CPU_ERR0_PCH_R_N")
	)
	(segment
		(start 319.48628 -56.744108)
		(end 320.01841 -56.211978)
		(width 0.12954)
		(layer "B.Cu")
		(net "H_CPU_ERR0_PCH_R_N")
	)
	(segment
		(start 316.15888 -58.511948)
		(end 316.84976 -58.511948)
		(width 0.12954)
		(layer "B.Cu")
		(net "H_CPU_ERR0_PCH_R_N")
	)
	(segment
		(start 320.170556 -56.211978)
		(end 320.996564 -56.211978)
		(width 0.12954)
		(layer "B.Cu")
		(net "H_CPU_ERR0_PCH_R_N")
	)
	(segment
		(start 316.84976 -58.511948)
		(end 318.6176 -56.744108)
		(width 0.12954)
		(layer "B.Cu")
		(net "H_CPU_ERR0_PCH_R_N")
	)
	(segment
		(start 320.01841 -56.211978)
		(end 320.170556 -56.211978)
		(width 0.12954)
		(layer "B.Cu")
		(net "H_CPU_ERR0_PCH_R_N")
	)
	(segment
		(start 318.6176 -56.744108)
		(end 319.48628 -56.744108)
		(width 0.12954)
		(layer "B.Cu")
		(net "H_CPU_ERR0_PCH_R_N")
	)
	(segment
		(start 324.648576 -54.422548)
		(end 325.724774 -55.498746)
		(width 0.12954)
		(layer "B.Cu")
		(net "H_CPU_ERR0_PCH_R_N")
	)
	(segment
		(start 328.626978 -55.498746)
		(end 327.593706 -55.498746)
		(width 0.12954)
		(layer "B.Cu")
		(net "H_CPU_ERR0_PCH_R_N")
	)
	(segment
		(start 146.252184 -95.976948)
		(end 160.543748 -95.976948)
		(width 0.127)
		(layer "In11.Cu")
		(net "H_CPU_ERR0_PCH_R_N")
	)
	(segment
		(start 188.445648 -87.658448)
		(end 191.701928 -90.914728)
		(width 0.127)
		(layer "In11.Cu")
		(net "H_CPU_ERR0_PCH_R_N")
	)
	(segment
		(start 312.62066 -61.559948)
		(end 313.11088 -61.559948)
		(width 0.127)
		(layer "In11.Cu")
		(net "H_CPU_ERR0_PCH_R_N")
	)
	(segment
		(start 232.05948 -71.999348)
		(end 240.36528 -71.999348)
		(width 0.127)
		(layer "In11.Cu")
		(net "H_CPU_ERR0_PCH_R_N")
	)
	(segment
		(start 303.56048 -66.030348)
		(end 304.72888 -64.861948)
		(width 0.127)
		(layer "In11.Cu")
		(net "H_CPU_ERR0_PCH_R_N")
	)
	(segment
		(start 215.212422 -88.846406)
		(end 232.05948 -71.999348)
		(width 0.127)
		(layer "In11.Cu")
		(net "H_CPU_ERR0_PCH_R_N")
	)
	(segment
		(start 304.72888 -64.861948)
		(end 310.134 -64.861948)
		(width 0.127)
		(layer "In11.Cu")
		(net "H_CPU_ERR0_PCH_R_N")
	)
	(segment
		(start 250.133866 -81.767934)
		(end 297.849798 -81.767934)
		(width 0.127)
		(layer "In11.Cu")
		(net "H_CPU_ERR0_PCH_R_N")
	)
	(segment
		(start 145.236184 -96.992948)
		(end 146.252184 -95.976948)
		(width 0.127)
		(layer "In11.Cu")
		(net "H_CPU_ERR0_PCH_R_N")
	)
	(segment
		(start 310.92394 -63.256668)
		(end 312.62066 -61.559948)
		(width 0.127)
		(layer "In11.Cu")
		(net "H_CPU_ERR0_PCH_R_N")
	)
	(segment
		(start 240.36528 -71.999348)
		(end 250.133866 -81.767934)
		(width 0.127)
		(layer "In11.Cu")
		(net "H_CPU_ERR0_PCH_R_N")
	)
	(segment
		(start 160.543748 -95.976948)
		(end 168.862248 -87.658448)
		(width 0.127)
		(layer "In11.Cu")
		(net "H_CPU_ERR0_PCH_R_N")
	)
	(segment
		(start 204.857858 -90.914728)
		(end 206.92618 -88.846406)
		(width 0.127)
		(layer "In11.Cu")
		(net "H_CPU_ERR0_PCH_R_N")
	)
	(segment
		(start 310.134 -64.861948)
		(end 310.92394 -64.072008)
		(width 0.127)
		(layer "In11.Cu")
		(net "H_CPU_ERR0_PCH_R_N")
	)
	(segment
		(start 303.56048 -76.057252)
		(end 303.56048 -66.030348)
		(width 0.127)
		(layer "In11.Cu")
		(net "H_CPU_ERR0_PCH_R_N")
	)
	(segment
		(start 206.92618 -88.846406)
		(end 215.212422 -88.846406)
		(width 0.127)
		(layer "In11.Cu")
		(net "H_CPU_ERR0_PCH_R_N")
	)
	(segment
		(start 297.849798 -81.767934)
		(end 303.56048 -76.057252)
		(width 0.127)
		(layer "In11.Cu")
		(net "H_CPU_ERR0_PCH_R_N")
	)
	(segment
		(start 310.92394 -64.072008)
		(end 310.92394 -63.256668)
		(width 0.127)
		(layer "In11.Cu")
		(net "H_CPU_ERR0_PCH_R_N")
	)
	(segment
		(start 313.11088 -61.559948)
		(end 316.15888 -58.511948)
		(width 0.127)
		(layer "In11.Cu")
		(net "H_CPU_ERR0_PCH_R_N")
	)
	(segment
		(start 168.862248 -87.658448)
		(end 188.445648 -87.658448)
		(width 0.127)
		(layer "In11.Cu")
		(net "H_CPU_ERR0_PCH_R_N")
	)
	(segment
		(start 145.21688 -96.992948)
		(end 145.236184 -96.992948)
		(width 0.127)
		(layer "In11.Cu")
		(net "H_CPU_ERR0_PCH_R_N")
	)
	(segment
		(start 191.701928 -90.914728)
		(end 204.857858 -90.914728)
		(width 0.127)
		(layer "In11.Cu")
		(net "H_CPU_ERR0_PCH_R_N")
	)
	(segment
		(start 139.14374 -105.275888)
		(end 139.2682 -105.151428)
		(width 0.12954)
		(layer "F.Cu")
		(net "H_CPU_ERR0_LVC1_R_N")
	)
	(segment
		(start 139.2682 -105.151428)
		(end 139.2682 -104.516428)
		(width 0.12954)
		(layer "F.Cu")
		(net "H_CPU_ERR0_LVC1_R_N")
	)
	(via
		(at 139.14374 -105.275888)
		(size 0.508)
		(drill 0.254)
		(layers "F.Cu" "B.Cu")
		(net "H_CPU_ERR0_LVC1_R_N")
	)
	(via
		(at 138.94308 -149.944328)
		(size 0.508)
		(drill 0.254)
		(layers "F.Cu" "B.Cu")
		(net "H_CPU_ERR0_LVC1_R_N")
	)
	(via
		(at 261.52602 -152.718008)
		(size 0.508)
		(drill 0.254)
		(layers "F.Cu" "B.Cu")
		(net "H_CPU_ERR0_LVC1_R_N")
	)
	(segment
		(start 121.105168 -151.153368)
		(end 120.52554 -150.57374)
		(width 0.12954)
		(layer "B.Cu")
		(net "H_CPU_ERR0_LVC1_R_N")
	)
	(segment
		(start 120.52554 -150.57374)
		(end 109.912912 -150.57374)
		(width 0.12954)
		(layer "B.Cu")
		(net "H_CPU_ERR0_LVC1_R_N")
	)
	(segment
		(start 109.912912 -150.57374)
		(end 84.212176 -176.274476)
		(width 0.12954)
		(layer "B.Cu")
		(net "H_CPU_ERR0_LVC1_R_N")
	)
	(segment
		(start 138.94308 -149.944328)
		(end 138.02741 -150.859998)
		(width 0.12954)
		(layer "B.Cu")
		(net "H_CPU_ERR0_LVC1_R_N")
	)
	(segment
		(start 84.212176 -178.400964)
		(end 82.46364 -180.1495)
		(width 0.12954)
		(layer "B.Cu")
		(net "H_CPU_ERR0_LVC1_R_N")
	)
	(segment
		(start 261.52602 -152.718008)
		(end 261.52602 -157.724856)
		(width 0.12954)
		(layer "B.Cu")
		(net "H_CPU_ERR0_LVC1_R_N")
	)
	(segment
		(start 133.735572 -151.153368)
		(end 121.105168 -151.153368)
		(width 0.12954)
		(layer "B.Cu")
		(net "H_CPU_ERR0_LVC1_R_N")
	)
	(segment
		(start 321.00139 -186.040268)
		(end 320.039492 -186.040268)
		(width 0.12954)
		(layer "B.Cu")
		(net "H_CPU_ERR0_LVC1_R_N")
	)
	(segment
		(start 307.406548 -172.44441)
		(end 320.039492 -185.077354)
		(width 0.12954)
		(layer "B.Cu")
		(net "H_CPU_ERR0_LVC1_R_N")
	)
	(segment
		(start 82.46364 -180.1495)
		(end 82.46364 -180.151024)
		(width 0.12954)
		(layer "B.Cu")
		(net "H_CPU_ERR0_LVC1_R_N")
	)
	(segment
		(start 82.46364 -180.151024)
		(end 82.462624 -180.151024)
		(width 0.12954)
		(layer "B.Cu")
		(net "H_CPU_ERR0_LVC1_R_N")
	)
	(segment
		(start 82.462624 -180.151024)
		(end 82.462624 -183.696102)
		(width 0.12954)
		(layer "B.Cu")
		(net "H_CPU_ERR0_LVC1_R_N")
	)
	(segment
		(start 276.245574 -172.44441)
		(end 307.406548 -172.44441)
		(width 0.12954)
		(layer "B.Cu")
		(net "H_CPU_ERR0_LVC1_R_N")
	)
	(segment
		(start 320.039492 -185.077354)
		(end 320.039492 -186.040268)
		(width 0.12954)
		(layer "B.Cu")
		(net "H_CPU_ERR0_LVC1_R_N")
	)
	(segment
		(start 84.212176 -176.274476)
		(end 84.212176 -178.400964)
		(width 0.12954)
		(layer "B.Cu")
		(net "H_CPU_ERR0_LVC1_R_N")
	)
	(segment
		(start 138.02741 -150.859998)
		(end 134.028942 -150.859998)
		(width 0.12954)
		(layer "B.Cu")
		(net "H_CPU_ERR0_LVC1_R_N")
	)
	(segment
		(start 261.52602 -157.724856)
		(end 276.245574 -172.44441)
		(width 0.12954)
		(layer "B.Cu")
		(net "H_CPU_ERR0_LVC1_R_N")
	)
	(segment
		(start 321.001898 -186.03976)
		(end 321.00139 -186.040268)
		(width 0.12954)
		(layer "B.Cu")
		(net "H_CPU_ERR0_LVC1_R_N")
	)
	(segment
		(start 134.028942 -150.859998)
		(end 133.735572 -151.153368)
		(width 0.12954)
		(layer "B.Cu")
		(net "H_CPU_ERR0_LVC1_R_N")
	)
	(segment
		(start 138.94308 -149.944328)
		(end 138.94308 -146.345148)
		(width 0.127)
		(layer "In2.Cu")
		(net "H_CPU_ERR0_LVC1_R_N")
	)
	(segment
		(start 137.14476 -107.274868)
		(end 139.14374 -105.275888)
		(width 0.127)
		(layer "In2.Cu")
		(net "H_CPU_ERR0_LVC1_R_N")
	)
	(segment
		(start 137.14476 -114.85118)
		(end 137.14476 -107.274868)
		(width 0.127)
		(layer "In2.Cu")
		(net "H_CPU_ERR0_LVC1_R_N")
	)
	(segment
		(start 138.94308 -146.345148)
		(end 138.20394 -145.606008)
		(width 0.127)
		(layer "In2.Cu")
		(net "H_CPU_ERR0_LVC1_R_N")
	)
	(segment
		(start 138.20394 -115.85702)
		(end 138.1506 -115.85702)
		(width 0.127)
		(layer "In2.Cu")
		(net "H_CPU_ERR0_LVC1_R_N")
	)
	(segment
		(start 138.1506 -115.85702)
		(end 137.14476 -114.85118)
		(width 0.127)
		(layer "In2.Cu")
		(net "H_CPU_ERR0_LVC1_R_N")
	)
	(segment
		(start 138.20394 -145.606008)
		(end 138.20394 -115.85702)
		(width 0.127)
		(layer "In2.Cu")
		(net "H_CPU_ERR0_LVC1_R_N")
	)
	(segment
		(start 257.56362 -153.048208)
		(end 258.55295 -152.058878)
		(width 0.127)
		(layer "In13.Cu")
		(net "H_CPU_ERR0_LVC1_R_N")
	)
	(segment
		(start 173.01718 -147.851368)
		(end 186.70016 -161.534348)
		(width 0.127)
		(layer "In13.Cu")
		(net "H_CPU_ERR0_LVC1_R_N")
	)
	(segment
		(start 215.916256 -153.048208)
		(end 257.56362 -153.048208)
		(width 0.127)
		(layer "In13.Cu")
		(net "H_CPU_ERR0_LVC1_R_N")
	)
	(segment
		(start 138.94308 -149.944328)
		(end 138.94308 -146.385788)
		(width 0.127)
		(layer "In13.Cu")
		(net "H_CPU_ERR0_LVC1_R_N")
	)
	(segment
		(start 152.738836 -147.851368)
		(end 173.01718 -147.851368)
		(width 0.127)
		(layer "In13.Cu")
		(net "H_CPU_ERR0_LVC1_R_N")
	)
	(segment
		(start 186.70016 -161.534348)
		(end 207.430116 -161.534348)
		(width 0.127)
		(layer "In13.Cu")
		(net "H_CPU_ERR0_LVC1_R_N")
	)
	(segment
		(start 138.94308 -146.385788)
		(end 141.73962 -143.589248)
		(width 0.127)
		(layer "In13.Cu")
		(net "H_CPU_ERR0_LVC1_R_N")
	)
	(segment
		(start 258.55295 -152.058878)
		(end 260.86689 -152.058878)
		(width 0.127)
		(layer "In13.Cu")
		(net "H_CPU_ERR0_LVC1_R_N")
	)
	(segment
		(start 207.430116 -161.534348)
		(end 215.916256 -153.048208)
		(width 0.127)
		(layer "In13.Cu")
		(net "H_CPU_ERR0_LVC1_R_N")
	)
	(segment
		(start 260.86689 -152.058878)
		(end 261.52602 -152.718008)
		(width 0.127)
		(layer "In13.Cu")
		(net "H_CPU_ERR0_LVC1_R_N")
	)
	(segment
		(start 141.73962 -143.589248)
		(end 148.476716 -143.589248)
		(width 0.127)
		(layer "In13.Cu")
		(net "H_CPU_ERR0_LVC1_R_N")
	)
	(segment
		(start 148.476716 -143.589248)
		(end 152.738836 -147.851368)
		(width 0.127)
		(layer "In13.Cu")
		(net "H_CPU_ERR0_LVC1_R_N")
	)
	(segment
		(start 138.89482 -100.104448)
		(end 138.89482 -102.436168)
		(width 0.12954)
		(layer "F.Cu")
		(net "H_CPU_ERR0_LVC1_N")
	)
	(segment
		(start 140.356082 -100.729542)
		(end 140.32992 -100.70338)
		(width 0.12954)
		(layer "F.Cu")
		(net "H_CPU_ERR0_LVC1_N")
	)
	(segment
		(start 140.32992 -99.847908)
		(end 140.20038 -99.718368)
		(width 0.12954)
		(layer "F.Cu")
		(net "H_CPU_ERR0_LVC1_N")
	)
	(segment
		(start 140.32992 -100.70338)
		(end 140.32992 -99.847908)
		(width 0.12954)
		(layer "F.Cu")
		(net "H_CPU_ERR0_LVC1_N")
	)
	(segment
		(start 140.20038 -99.718368)
		(end 139.2809 -99.718368)
		(width 0.12954)
		(layer "F.Cu")
		(net "H_CPU_ERR0_LVC1_N")
	)
	(segment
		(start 139.2809 -99.718368)
		(end 138.89482 -100.104448)
		(width 0.12954)
		(layer "F.Cu")
		(net "H_CPU_ERR0_LVC1_N")
	)
	(segment
		(start 138.89482 -102.436168)
		(end 138.89482 -102.509828)
		(width 0.12954)
		(layer "F.Cu")
		(net "H_CPU_ERR0_LVC1_N")
	)
	(segment
		(start 138.89482 -102.509828)
		(end 139.2682 -102.883208)
		(width 0.12954)
		(layer "F.Cu")
		(net "H_CPU_ERR0_LVC1_N")
	)
	(segment
		(start 139.2682 -102.883208)
		(end 139.2682 -103.716328)
		(width 0.12954)
		(layer "F.Cu")
		(net "H_CPU_ERR0_LVC1_N")
	)
	(via
		(at 138.89482 -102.436168)
		(size 0.762)
		(drill 0.381)
		(layers "F.Cu" "B.Cu")
		(net "H_CPU_ERR0_LVC1_N")
	)
	(segment
		(start 116.64188 -100.015548)
		(end 116.64188 -99.157028)
		(width 0.12954)
		(layer "F.Cu")
		(net "H_CPU_CATERR_LVC1_R_N")
	)
	(segment
		(start 115.86972 -99.243388)
		(end 115.86972 -98.425762)
		(width 0.12954)
		(layer "F.Cu")
		(net "H_CPU_CATERR_LVC1_R_N")
	)
	(segment
		(start 116.519706 -99.034854)
		(end 116.519706 -98.425762)
		(width 0.12954)
		(layer "F.Cu")
		(net "H_CPU_CATERR_LVC1_R_N")
	)
	(segment
		(start 116.64188 -99.157028)
		(end 116.519706 -99.034854)
		(width 0.12954)
		(layer "F.Cu")
		(net "H_CPU_CATERR_LVC1_R_N")
	)
	(segment
		(start 116.64188 -100.015548)
		(end 115.86972 -99.243388)
		(width 0.12954)
		(layer "F.Cu")
		(net "H_CPU_CATERR_LVC1_R_N")
	)
	(via
		(at 268.27988 -153.683208)
		(size 0.508)
		(drill 0.254)
		(layers "F.Cu" "B.Cu")
		(net "H_CPU_CATERR_LVC1_R_N")
	)
	(via
		(at 116.64188 -100.015548)
		(size 0.508)
		(drill 0.254)
		(layers "F.Cu" "B.Cu")
		(net "H_CPU_CATERR_LVC1_R_N")
	)
	(via
		(at 119.60352 -145.463768)
		(size 0.508)
		(drill 0.254)
		(layers "F.Cu" "B.Cu")
		(net "H_CPU_CATERR_LVC1_R_N")
	)
	(segment
		(start 329.170538 -185.9661)
		(end 329.170538 -184.9882)
		(width 0.12954)
		(layer "B.Cu")
		(net "H_CPU_CATERR_LVC1_R_N")
	)
	(segment
		(start 329.673458 -184.48528)
		(end 329.170538 -184.9882)
		(width 0.12954)
		(layer "B.Cu")
		(net "H_CPU_CATERR_LVC1_R_N")
	)
	(segment
		(start 73.917302 -180.983382)
		(end 73.917302 -180.653944)
		(width 0.12954)
		(layer "B.Cu")
		(net "H_CPU_CATERR_LVC1_R_N")
	)
	(segment
		(start 79.077566 -176.353978)
		(end 79.077566 -174.227998)
		(width 0.12954)
		(layer "B.Cu")
		(net "H_CPU_CATERR_LVC1_R_N")
	)
	(segment
		(start 73.917302 -180.653944)
		(end 74.829416 -179.74183)
		(width 0.12954)
		(layer "B.Cu")
		(net "H_CPU_CATERR_LVC1_R_N")
	)
	(segment
		(start 329.673458 -183.75757)
		(end 329.673458 -184.48528)
		(width 0.12954)
		(layer "B.Cu")
		(net "H_CPU_CATERR_LVC1_R_N")
	)
	(segment
		(start 278.095456 -166.22395)
		(end 311.11698 -166.22395)
		(width 0.12954)
		(layer "B.Cu")
		(net "H_CPU_CATERR_LVC1_R_N")
	)
	(segment
		(start 75.058778 -179.74183)
		(end 75.724258 -179.07635)
		(width 0.12954)
		(layer "B.Cu")
		(net "H_CPU_CATERR_LVC1_R_N")
	)
	(segment
		(start 268.0208 -156.149294)
		(end 278.095456 -166.22395)
		(width 0.12954)
		(layer "B.Cu")
		(net "H_CPU_CATERR_LVC1_R_N")
	)
	(segment
		(start 329.268836 -183.352948)
		(end 329.673458 -183.75757)
		(width 0.12954)
		(layer "B.Cu")
		(net "H_CPU_CATERR_LVC1_R_N")
	)
	(segment
		(start 311.11698 -166.22395)
		(end 328.245978 -183.352948)
		(width 0.12954)
		(layer "B.Cu")
		(net "H_CPU_CATERR_LVC1_R_N")
	)
	(segment
		(start 79.077566 -174.227998)
		(end 107.841796 -145.463768)
		(width 0.12954)
		(layer "B.Cu")
		(net "H_CPU_CATERR_LVC1_R_N")
	)
	(segment
		(start 268.27988 -153.683208)
		(end 268.0208 -153.942288)
		(width 0.12954)
		(layer "B.Cu")
		(net "H_CPU_CATERR_LVC1_R_N")
	)
	(segment
		(start 73.902062 -181.4195)
		(end 73.902062 -180.998622)
		(width 0.12954)
		(layer "B.Cu")
		(net "H_CPU_CATERR_LVC1_R_N")
	)
	(segment
		(start 107.841796 -145.463768)
		(end 119.60352 -145.463768)
		(width 0.12954)
		(layer "B.Cu")
		(net "H_CPU_CATERR_LVC1_R_N")
	)
	(segment
		(start 268.0208 -153.942288)
		(end 268.0208 -156.149294)
		(width 0.12954)
		(layer "B.Cu")
		(net "H_CPU_CATERR_LVC1_R_N")
	)
	(segment
		(start 74.829416 -179.74183)
		(end 74.850498 -179.74183)
		(width 0.12954)
		(layer "B.Cu")
		(net "H_CPU_CATERR_LVC1_R_N")
	)
	(segment
		(start 74.850498 -179.74183)
		(end 75.058778 -179.74183)
		(width 0.12954)
		(layer "B.Cu")
		(net "H_CPU_CATERR_LVC1_R_N")
	)
	(segment
		(start 328.245978 -183.352948)
		(end 329.268836 -183.352948)
		(width 0.12954)
		(layer "B.Cu")
		(net "H_CPU_CATERR_LVC1_R_N")
	)
	(segment
		(start 76.355194 -179.07635)
		(end 79.077566 -176.353978)
		(width 0.12954)
		(layer "B.Cu")
		(net "H_CPU_CATERR_LVC1_R_N")
	)
	(segment
		(start 73.902062 -180.998622)
		(end 73.917302 -180.983382)
		(width 0.12954)
		(layer "B.Cu")
		(net "H_CPU_CATERR_LVC1_R_N")
	)
	(segment
		(start 75.724258 -179.07635)
		(end 76.355194 -179.07635)
		(width 0.12954)
		(layer "B.Cu")
		(net "H_CPU_CATERR_LVC1_R_N")
	)
	(segment
		(start 117.747034 -107.323382)
		(end 118.30812 -106.762296)
		(width 0.127)
		(layer "In2.Cu")
		(net "H_CPU_CATERR_LVC1_R_N")
	)
	(segment
		(start 118.30812 -106.762296)
		(end 118.30812 -102.52456)
		(width 0.127)
		(layer "In2.Cu")
		(net "H_CPU_CATERR_LVC1_R_N")
	)
	(segment
		(start 117.747034 -113.292382)
		(end 117.747034 -107.323382)
		(width 0.127)
		(layer "In2.Cu")
		(net "H_CPU_CATERR_LVC1_R_N")
	)
	(segment
		(start 116.64188 -100.85832)
		(end 116.64188 -100.015548)
		(width 0.127)
		(layer "In2.Cu")
		(net "H_CPU_CATERR_LVC1_R_N")
	)
	(segment
		(start 119.60352 -145.463768)
		(end 119.60352 -115.148868)
		(width 0.127)
		(layer "In2.Cu")
		(net "H_CPU_CATERR_LVC1_R_N")
	)
	(segment
		(start 118.30812 -102.52456)
		(end 116.64188 -100.85832)
		(width 0.127)
		(layer "In2.Cu")
		(net "H_CPU_CATERR_LVC1_R_N")
	)
	(segment
		(start 119.60352 -115.148868)
		(end 117.747034 -113.292382)
		(width 0.127)
		(layer "In2.Cu")
		(net "H_CPU_CATERR_LVC1_R_N")
	)
	(segment
		(start 190.39332 -165.783768)
		(end 187.52312 -168.653968)
		(width 0.127)
		(layer "In13.Cu")
		(net "H_CPU_CATERR_LVC1_R_N")
	)
	(segment
		(start 175.62068 -169.883328)
		(end 135.5217 -169.883328)
		(width 0.127)
		(layer "In13.Cu")
		(net "H_CPU_CATERR_LVC1_R_N")
	)
	(segment
		(start 264.2997 -157.869128)
		(end 217.223594 -157.869128)
		(width 0.127)
		(layer "In13.Cu")
		(net "H_CPU_CATERR_LVC1_R_N")
	)
	(segment
		(start 217.223594 -157.869128)
		(end 209.308954 -165.783768)
		(width 0.127)
		(layer "In13.Cu")
		(net "H_CPU_CATERR_LVC1_R_N")
	)
	(segment
		(start 119.6213 -152.408128)
		(end 119.2784 -152.065228)
		(width 0.127)
		(layer "In13.Cu")
		(net "H_CPU_CATERR_LVC1_R_N")
	)
	(segment
		(start 135.5217 -169.883328)
		(end 119.6213 -153.982928)
		(width 0.127)
		(layer "In13.Cu")
		(net "H_CPU_CATERR_LVC1_R_N")
	)
	(segment
		(start 119.6213 -153.982928)
		(end 119.6213 -152.408128)
		(width 0.127)
		(layer "In13.Cu")
		(net "H_CPU_CATERR_LVC1_R_N")
	)
	(segment
		(start 187.52312 -168.653968)
		(end 176.85004 -168.653968)
		(width 0.127)
		(layer "In13.Cu")
		(net "H_CPU_CATERR_LVC1_R_N")
	)
	(segment
		(start 209.308954 -165.783768)
		(end 190.39332 -165.783768)
		(width 0.127)
		(layer "In13.Cu")
		(net "H_CPU_CATERR_LVC1_R_N")
	)
	(segment
		(start 268.27988 -153.683208)
		(end 268.27988 -153.888948)
		(width 0.127)
		(layer "In13.Cu")
		(net "H_CPU_CATERR_LVC1_R_N")
	)
	(segment
		(start 176.85004 -168.653968)
		(end 175.62068 -169.883328)
		(width 0.127)
		(layer "In13.Cu")
		(net "H_CPU_CATERR_LVC1_R_N")
	)
	(segment
		(start 119.2784 -152.065228)
		(end 119.2784 -145.788888)
		(width 0.127)
		(layer "In13.Cu")
		(net "H_CPU_CATERR_LVC1_R_N")
	)
	(segment
		(start 268.27988 -153.888948)
		(end 264.2997 -157.869128)
		(width 0.127)
		(layer "In13.Cu")
		(net "H_CPU_CATERR_LVC1_R_N")
	)
	(segment
		(start 119.2784 -145.788888)
		(end 119.60352 -145.463768)
		(width 0.127)
		(layer "In13.Cu")
		(net "H_CPU_CATERR_LVC1_R_N")
	)
	(segment
		(start 124.64288 -92.274898)
		(end 124.64288 -91.658948)
		(width 0.12954)
		(layer "F.Cu")
		(net "H_CPU1_THERMTRIP_LVC1_R_N")
	)
	(segment
		(start 108.461048 -265.592306)
		(end 108.461048 -266.127992)
		(width 0.12954)
		(layer "F.Cu")
		(net "H_CPU1_THERMTRIP_LVC1_R_N")
	)
	(segment
		(start 125.65888 -92.274898)
		(end 124.64288 -92.274898)
		(width 0.12954)
		(layer "F.Cu")
		(net "H_CPU1_THERMTRIP_LVC1_R_N")
	)
	(segment
		(start 108.461048 -266.127992)
		(end 108.460794 -266.128246)
		(width 0.12954)
		(layer "F.Cu")
		(net "H_CPU1_THERMTRIP_LVC1_R_N")
	)
	(via
		(at 124.64288 -91.658948)
		(size 0.508)
		(drill 0.254)
		(layers "F.Cu" "B.Cu")
		(net "H_CPU1_THERMTRIP_LVC1_R_N")
	)
	(via
		(at 108.460794 -266.128246)
		(size 0.4572)
		(drill 0.2032)
		(layers "F.Cu" "B.Cu")
		(net "H_CPU1_THERMTRIP_LVC1_R_N")
	)
	(via
		(at 78.953106 -259.986526)
		(size 0.6604)
		(drill 0.3302)
		(layers "F.Cu" "B.Cu")
		(net "H_CPU1_THERMTRIP_LVC1_R_N")
	)
	(via
		(at 57.76722 -182.822088)
		(size 0.508)
		(drill 0.254)
		(layers "F.Cu" "B.Cu")
		(net "H_CPU1_THERMTRIP_LVC1_R_N")
	)
	(segment
		(start 89.429844 -260.83768)
		(end 89.416382 -260.845554)
		(width 0.0889)
		(layer "B.Cu")
		(net "H_CPU1_THERMTRIP_LVC1_R_N")
	)
	(segment
		(start 87.080344 -260.83768)
		(end 86.640162 -260.83768)
		(width 0.12954)
		(layer "B.Cu")
		(net "H_CPU1_THERMTRIP_LVC1_R_N")
	)
	(segment
		(start 94.612206 -260.845554)
		(end 94.598744 -260.83768)
		(width 0.0889)
		(layer "B.Cu")
		(net "H_CPU1_THERMTRIP_LVC1_R_N")
	)
	(segment
		(start 91.309444 -260.83768)
		(end 91.295982 -260.845554)
		(width 0.0889)
		(layer "B.Cu")
		(net "H_CPU1_THERMTRIP_LVC1_R_N")
	)
	(segment
		(start 66.104516 -242.103148)
		(end 69.981318 -242.103148)
		(width 0.12954)
		(layer "B.Cu")
		(net "H_CPU1_THERMTRIP_LVC1_R_N")
	)
	(segment
		(start 107.803696 -265.638534)
		(end 107.80395 -265.638534)
		(width 0.0889)
		(layer "B.Cu")
		(net "H_CPU1_THERMTRIP_LVC1_R_N")
	)
	(segment
		(start 108.460794 -266.128246)
		(end 108.460794 -266.127992)
		(width 0.0889)
		(layer "B.Cu")
		(net "H_CPU1_THERMTRIP_LVC1_R_N")
	)
	(segment
		(start 62.73546 -240.129568)
		(end 62.93104 -240.325148)
		(width 0.12954)
		(layer "B.Cu")
		(net "H_CPU1_THERMTRIP_LVC1_R_N")
	)
	(segment
		(start 59.06008 -238.724948)
		(end 59.28868 -238.496348)
		(width 0.12954)
		(layer "B.Cu")
		(net "H_CPU1_THERMTRIP_LVC1_R_N")
	)
	(segment
		(start 93.189044 -260.83768)
		(end 93.175582 -260.845554)
		(width 0.0889)
		(layer "B.Cu")
		(net "H_CPU1_THERMTRIP_LVC1_R_N")
	)
	(segment
		(start 104.326944 -264.500106)
		(end 104.326944 -264.17905)
		(width 0.0889)
		(layer "B.Cu")
		(net "H_CPU1_THERMTRIP_LVC1_R_N")
	)
	(segment
		(start 107.832398 -265.65479)
		(end 107.803696 -265.638534)
		(width 0.0889)
		(layer "B.Cu")
		(net "H_CPU1_THERMTRIP_LVC1_R_N")
	)
	(segment
		(start 69.981318 -242.103148)
		(end 70.286118 -242.229386)
		(width 0.12954)
		(layer "B.Cu")
		(net "H_CPU1_THERMTRIP_LVC1_R_N")
	)
	(segment
		(start 57.76722 -198.488808)
		(end 55.70728 -200.548748)
		(width 0.12954)
		(layer "B.Cu")
		(net "H_CPU1_THERMTRIP_LVC1_R_N")
	)
	(segment
		(start 104.326944 -264.17905)
		(end 104.326436 -264.178542)
		(width 0.0889)
		(layer "B.Cu")
		(net "H_CPU1_THERMTRIP_LVC1_R_N")
	)
	(segment
		(start 96.008444 -260.83768)
		(end 95.994982 -260.845554)
		(width 0.0889)
		(layer "B.Cu")
		(net "H_CPU1_THERMTRIP_LVC1_R_N")
	)
	(segment
		(start 100.707444 -260.83768)
		(end 100.693982 -260.845554)
		(width 0.0889)
		(layer "B.Cu")
		(net "H_CPU1_THERMTRIP_LVC1_R_N")
	)
	(segment
		(start 102.111048 -260.83768)
		(end 101.177344 -260.83768)
		(width 0.0889)
		(layer "B.Cu")
		(net "H_CPU1_THERMTRIP_LVC1_R_N")
	)
	(segment
		(start 60.45708 -238.496348)
		(end 62.0903 -240.129568)
		(width 0.12954)
		(layer "B.Cu")
		(net "H_CPU1_THERMTRIP_LVC1_R_N")
	)
	(segment
		(start 74.30262 -255.821688)
		(end 78.467458 -259.986526)
		(width 0.12954)
		(layer "B.Cu")
		(net "H_CPU1_THERMTRIP_LVC1_R_N")
	)
	(segment
		(start 99.767644 -260.83768)
		(end 99.754182 -260.845554)
		(width 0.0889)
		(layer "B.Cu")
		(net "H_CPU1_THERMTRIP_LVC1_R_N")
	)
	(segment
		(start 74.30262 -246.245888)
		(end 74.30262 -255.821688)
		(width 0.12954)
		(layer "B.Cu")
		(net "H_CPU1_THERMTRIP_LVC1_R_N")
	)
	(segment
		(start 90.369644 -260.83768)
		(end 90.356182 -260.845554)
		(width 0.0889)
		(layer "B.Cu")
		(net "H_CPU1_THERMTRIP_LVC1_R_N")
	)
	(segment
		(start 94.128844 -260.83768)
		(end 94.115382 -260.845554)
		(width 0.0889)
		(layer "B.Cu")
		(net "H_CPU1_THERMTRIP_LVC1_R_N")
	)
	(segment
		(start 62.93104 -240.325148)
		(end 64.326516 -240.325148)
		(width 0.12954)
		(layer "B.Cu")
		(net "H_CPU1_THERMTRIP_LVC1_R_N")
	)
	(segment
		(start 62.0903 -240.129568)
		(end 62.73546 -240.129568)
		(width 0.12954)
		(layer "B.Cu")
		(net "H_CPU1_THERMTRIP_LVC1_R_N")
	)
	(segment
		(start 57.76722 -182.822088)
		(end 57.76722 -198.488808)
		(width 0.12954)
		(layer "B.Cu")
		(net "H_CPU1_THERMTRIP_LVC1_R_N")
	)
	(segment
		(start 97.888044 -260.83768)
		(end 97.874582 -260.845554)
		(width 0.0889)
		(layer "B.Cu")
		(net "H_CPU1_THERMTRIP_LVC1_R_N")
	)
	(segment
		(start 102.761542 -261.488174)
		(end 102.111048 -260.83768)
		(width 0.0889)
		(layer "B.Cu")
		(net "H_CPU1_THERMTRIP_LVC1_R_N")
	)
	(segment
		(start 107.33405 -264.824718)
		(end 107.333796 -264.824718)
		(width 0.0889)
		(layer "B.Cu")
		(net "H_CPU1_THERMTRIP_LVC1_R_N")
	)
	(segment
		(start 104.326436 -264.178542)
		(end 104.326436 -264.087102)
		(width 0.0889)
		(layer "B.Cu")
		(net "H_CPU1_THERMTRIP_LVC1_R_N")
	)
	(segment
		(start 58.62828 -238.724948)
		(end 59.06008 -238.724948)
		(width 0.12954)
		(layer "B.Cu")
		(net "H_CPU1_THERMTRIP_LVC1_R_N")
	)
	(segment
		(start 55.70728 -200.548748)
		(end 55.70728 -235.803948)
		(width 0.12954)
		(layer "B.Cu")
		(net "H_CPU1_THERMTRIP_LVC1_R_N")
	)
	(segment
		(start 107.616498 -265.314176)
		(end 107.616498 -265.30427)
		(width 0.0889)
		(layer "B.Cu")
		(net "H_CPU1_THERMTRIP_LVC1_R_N")
	)
	(segment
		(start 64.326516 -240.325148)
		(end 66.104516 -242.103148)
		(width 0.12954)
		(layer "B.Cu")
		(net "H_CPU1_THERMTRIP_LVC1_R_N")
	)
	(segment
		(start 59.28868 -238.496348)
		(end 60.45708 -238.496348)
		(width 0.12954)
		(layer "B.Cu")
		(net "H_CPU1_THERMTRIP_LVC1_R_N")
	)
	(segment
		(start 105.454196 -264.824718)
		(end 105.439464 -264.816082)
		(width 0.0889)
		(layer "B.Cu")
		(net "H_CPU1_THERMTRIP_LVC1_R_N")
	)
	(segment
		(start 102.761542 -262.522208)
		(end 102.761542 -261.488174)
		(width 0.0889)
		(layer "B.Cu")
		(net "H_CPU1_THERMTRIP_LVC1_R_N")
	)
	(segment
		(start 106.393996 -264.824718)
		(end 106.379264 -264.816082)
		(width 0.0889)
		(layer "B.Cu")
		(net "H_CPU1_THERMTRIP_LVC1_R_N")
	)
	(segment
		(start 108.460794 -266.127992)
		(end 107.832398 -265.65479)
		(width 0.0889)
		(layer "B.Cu")
		(net "H_CPU1_THERMTRIP_LVC1_R_N")
	)
	(segment
		(start 78.467458 -259.986526)
		(end 78.953106 -259.986526)
		(width 0.12954)
		(layer "B.Cu")
		(net "H_CPU1_THERMTRIP_LVC1_R_N")
	)
	(segment
		(start 85.789008 -259.986526)
		(end 78.953106 -259.986526)
		(width 0.12954)
		(layer "B.Cu")
		(net "H_CPU1_THERMTRIP_LVC1_R_N")
	)
	(segment
		(start 107.80395 -265.638534)
		(end 107.79506 -265.633454)
		(width 0.0889)
		(layer "B.Cu")
		(net "H_CPU1_THERMTRIP_LVC1_R_N")
	)
	(segment
		(start 96.491806 -260.845554)
		(end 96.478344 -260.83768)
		(width 0.0889)
		(layer "B.Cu")
		(net "H_CPU1_THERMTRIP_LVC1_R_N")
	)
	(segment
		(start 104.326436 -264.087102)
		(end 102.761542 -262.522208)
		(width 0.0889)
		(layer "B.Cu")
		(net "H_CPU1_THERMTRIP_LVC1_R_N")
	)
	(segment
		(start 70.286118 -242.229386)
		(end 74.30262 -246.245888)
		(width 0.12954)
		(layer "B.Cu")
		(net "H_CPU1_THERMTRIP_LVC1_R_N")
	)
	(segment
		(start 55.70728 -235.803948)
		(end 58.62828 -238.724948)
		(width 0.12954)
		(layer "B.Cu")
		(net "H_CPU1_THERMTRIP_LVC1_R_N")
	)
	(segment
		(start 86.640162 -260.83768)
		(end 85.789008 -259.986526)
		(width 0.12954)
		(layer "B.Cu")
		(net "H_CPU1_THERMTRIP_LVC1_R_N")
	)
	(arc
		(start 88.020144 -260.83768)
		(mid 87.785194 -260.774754)
		(end 87.550244 -260.83768)
		(width 0.0889)
		(layer "B.Cu")
		(net "H_CPU1_THERMTRIP_LVC1_R_N")
	)
	(arc
		(start 90.356182 -260.845554)
		(mid 90.126929 -260.900798)
		(end 89.899744 -260.83768)
		(width 0.0889)
		(layer "B.Cu")
		(net "H_CPU1_THERMTRIP_LVC1_R_N")
	)
	(arc
		(start 99.297744 -260.83768)
		(mid 99.062794 -260.774754)
		(end 98.827844 -260.83768)
		(width 0.0889)
		(layer "B.Cu")
		(net "H_CPU1_THERMTRIP_LVC1_R_N")
	)
	(arc
		(start 97.418144 -260.83768)
		(mid 97.183194 -260.774754)
		(end 96.948244 -260.83768)
		(width 0.0889)
		(layer "B.Cu")
		(net "H_CPU1_THERMTRIP_LVC1_R_N")
	)
	(arc
		(start 95.068644 -260.83768)
		(mid 94.841457 -260.900698)
		(end 94.612206 -260.845554)
		(width 0.0889)
		(layer "B.Cu")
		(net "H_CPU1_THERMTRIP_LVC1_R_N")
	)
	(arc
		(start 89.899744 -260.83768)
		(mid 89.664794 -260.774754)
		(end 89.429844 -260.83768)
		(width 0.0889)
		(layer "B.Cu")
		(net "H_CPU1_THERMTRIP_LVC1_R_N")
	)
	(arc
		(start 107.616498 -265.30427)
		(mid 107.538387 -265.027321)
		(end 107.33405 -264.824718)
		(width 0.0889)
		(layer "B.Cu")
		(net "H_CPU1_THERMTRIP_LVC1_R_N")
	)
	(arc
		(start 91.295982 -260.845554)
		(mid 91.066729 -260.900798)
		(end 90.839544 -260.83768)
		(width 0.0889)
		(layer "B.Cu")
		(net "H_CPU1_THERMTRIP_LVC1_R_N")
	)
	(arc
		(start 104.888792 -264.824718)
		(mid 104.514207 -264.824609)
		(end 104.326944 -264.500106)
		(width 0.0889)
		(layer "B.Cu")
		(net "H_CPU1_THERMTRIP_LVC1_R_N")
	)
	(arc
		(start 96.948244 -260.83768)
		(mid 96.721057 -260.900698)
		(end 96.491806 -260.845554)
		(width 0.0889)
		(layer "B.Cu")
		(net "H_CPU1_THERMTRIP_LVC1_R_N")
	)
	(arc
		(start 99.754182 -260.845554)
		(mid 99.524929 -260.900798)
		(end 99.297744 -260.83768)
		(width 0.0889)
		(layer "B.Cu")
		(net "H_CPU1_THERMTRIP_LVC1_R_N")
	)
	(arc
		(start 97.874582 -260.845554)
		(mid 97.645329 -260.900798)
		(end 97.418144 -260.83768)
		(width 0.0889)
		(layer "B.Cu")
		(net "H_CPU1_THERMTRIP_LVC1_R_N")
	)
	(arc
		(start 100.693982 -260.845554)
		(mid 100.464729 -260.900798)
		(end 100.237544 -260.83768)
		(width 0.0889)
		(layer "B.Cu")
		(net "H_CPU1_THERMTRIP_LVC1_R_N")
	)
	(arc
		(start 94.115382 -260.845554)
		(mid 93.886129 -260.900798)
		(end 93.658944 -260.83768)
		(width 0.0889)
		(layer "B.Cu")
		(net "H_CPU1_THERMTRIP_LVC1_R_N")
	)
	(arc
		(start 98.357944 -260.83768)
		(mid 98.122994 -260.774754)
		(end 97.888044 -260.83768)
		(width 0.0889)
		(layer "B.Cu")
		(net "H_CPU1_THERMTRIP_LVC1_R_N")
	)
	(arc
		(start 101.177344 -260.83768)
		(mid 100.942394 -260.774754)
		(end 100.707444 -260.83768)
		(width 0.0889)
		(layer "B.Cu")
		(net "H_CPU1_THERMTRIP_LVC1_R_N")
	)
	(arc
		(start 95.538544 -260.83768)
		(mid 95.303594 -260.774754)
		(end 95.068644 -260.83768)
		(width 0.0889)
		(layer "B.Cu")
		(net "H_CPU1_THERMTRIP_LVC1_R_N")
	)
	(arc
		(start 107.79506 -265.633454)
		(mid 107.664146 -265.497094)
		(end 107.616498 -265.314176)
		(width 0.0889)
		(layer "B.Cu")
		(net "H_CPU1_THERMTRIP_LVC1_R_N")
	)
	(arc
		(start 100.237544 -260.83768)
		(mid 100.002594 -260.774754)
		(end 99.767644 -260.83768)
		(width 0.0889)
		(layer "B.Cu")
		(net "H_CPU1_THERMTRIP_LVC1_R_N")
	)
	(arc
		(start 107.333796 -264.824718)
		(mid 107.051094 -264.748942)
		(end 106.768392 -264.824718)
		(width 0.0889)
		(layer "B.Cu")
		(net "H_CPU1_THERMTRIP_LVC1_R_N")
	)
	(arc
		(start 88.959944 -260.83768)
		(mid 88.724994 -260.774754)
		(end 88.490044 -260.83768)
		(width 0.0889)
		(layer "B.Cu")
		(net "H_CPU1_THERMTRIP_LVC1_R_N")
	)
	(arc
		(start 88.490044 -260.83768)
		(mid 88.255094 -260.90064)
		(end 88.020144 -260.83768)
		(width 0.0889)
		(layer "B.Cu")
		(net "H_CPU1_THERMTRIP_LVC1_R_N")
	)
	(arc
		(start 106.379264 -264.816082)
		(mid 106.102789 -264.748762)
		(end 105.828592 -264.824718)
		(width 0.0889)
		(layer "B.Cu")
		(net "H_CPU1_THERMTRIP_LVC1_R_N")
	)
	(arc
		(start 95.994982 -260.845554)
		(mid 95.765729 -260.900798)
		(end 95.538544 -260.83768)
		(width 0.0889)
		(layer "B.Cu")
		(net "H_CPU1_THERMTRIP_LVC1_R_N")
	)
	(arc
		(start 92.719144 -260.83768)
		(mid 92.484194 -260.774754)
		(end 92.249244 -260.83768)
		(width 0.0889)
		(layer "B.Cu")
		(net "H_CPU1_THERMTRIP_LVC1_R_N")
	)
	(arc
		(start 93.658944 -260.83768)
		(mid 93.423994 -260.774754)
		(end 93.189044 -260.83768)
		(width 0.0889)
		(layer "B.Cu")
		(net "H_CPU1_THERMTRIP_LVC1_R_N")
	)
	(arc
		(start 92.249244 -260.83768)
		(mid 92.014294 -260.90064)
		(end 91.779344 -260.83768)
		(width 0.0889)
		(layer "B.Cu")
		(net "H_CPU1_THERMTRIP_LVC1_R_N")
	)
	(arc
		(start 98.827844 -260.83768)
		(mid 98.592894 -260.90064)
		(end 98.357944 -260.83768)
		(width 0.0889)
		(layer "B.Cu")
		(net "H_CPU1_THERMTRIP_LVC1_R_N")
	)
	(arc
		(start 94.598744 -260.83768)
		(mid 94.363794 -260.774754)
		(end 94.128844 -260.83768)
		(width 0.0889)
		(layer "B.Cu")
		(net "H_CPU1_THERMTRIP_LVC1_R_N")
	)
	(arc
		(start 91.779344 -260.83768)
		(mid 91.544394 -260.774754)
		(end 91.309444 -260.83768)
		(width 0.0889)
		(layer "B.Cu")
		(net "H_CPU1_THERMTRIP_LVC1_R_N")
	)
	(arc
		(start 105.828592 -264.824718)
		(mid 105.641394 -264.874861)
		(end 105.454196 -264.824718)
		(width 0.0889)
		(layer "B.Cu")
		(net "H_CPU1_THERMTRIP_LVC1_R_N")
	)
	(arc
		(start 89.416382 -260.845554)
		(mid 89.187129 -260.900798)
		(end 88.959944 -260.83768)
		(width 0.0889)
		(layer "B.Cu")
		(net "H_CPU1_THERMTRIP_LVC1_R_N")
	)
	(arc
		(start 90.839544 -260.83768)
		(mid 90.604594 -260.774754)
		(end 90.369644 -260.83768)
		(width 0.0889)
		(layer "B.Cu")
		(net "H_CPU1_THERMTRIP_LVC1_R_N")
	)
	(arc
		(start 105.439464 -264.816082)
		(mid 105.162989 -264.748762)
		(end 104.888792 -264.824718)
		(width 0.0889)
		(layer "B.Cu")
		(net "H_CPU1_THERMTRIP_LVC1_R_N")
	)
	(arc
		(start 106.768392 -264.824718)
		(mid 106.581194 -264.874861)
		(end 106.393996 -264.824718)
		(width 0.0889)
		(layer "B.Cu")
		(net "H_CPU1_THERMTRIP_LVC1_R_N")
	)
	(arc
		(start 93.175582 -260.845554)
		(mid 92.946329 -260.900798)
		(end 92.719144 -260.83768)
		(width 0.0889)
		(layer "B.Cu")
		(net "H_CPU1_THERMTRIP_LVC1_R_N")
	)
	(arc
		(start 96.478344 -260.83768)
		(mid 96.243394 -260.774754)
		(end 96.008444 -260.83768)
		(width 0.0889)
		(layer "B.Cu")
		(net "H_CPU1_THERMTRIP_LVC1_R_N")
	)
	(arc
		(start 87.550244 -260.83768)
		(mid 87.315294 -260.90064)
		(end 87.080344 -260.83768)
		(width 0.0889)
		(layer "B.Cu")
		(net "H_CPU1_THERMTRIP_LVC1_R_N")
	)
	(segment
		(start 123.896882 -92.404946)
		(end 124.64288 -91.658948)
		(width 0.127)
		(layer "In4.Cu")
		(net "H_CPU1_THERMTRIP_LVC1_R_N")
	)
	(segment
		(start 111.66094 -139.873736)
		(end 111.66094 -101.084888)
		(width 0.127)
		(layer "In4.Cu")
		(net "H_CPU1_THERMTRIP_LVC1_R_N")
	)
	(segment
		(start 66.02476 -178.069748)
		(end 66.54038 -177.554128)
		(width 0.127)
		(layer "In4.Cu")
		(net "H_CPU1_THERMTRIP_LVC1_R_N")
	)
	(segment
		(start 111.66094 -101.084888)
		(end 115.130834 -97.614994)
		(width 0.127)
		(layer "In4.Cu")
		(net "H_CPU1_THERMTRIP_LVC1_R_N")
	)
	(segment
		(start 57.76722 -182.822088)
		(end 58.4962 -182.822088)
		(width 0.127)
		(layer "In4.Cu")
		(net "H_CPU1_THERMTRIP_LVC1_R_N")
	)
	(segment
		(start 118.780052 -92.404946)
		(end 123.896882 -92.404946)
		(width 0.127)
		(layer "In4.Cu")
		(net "H_CPU1_THERMTRIP_LVC1_R_N")
	)
	(segment
		(start 78.417928 -173.116748)
		(end 111.66094 -139.873736)
		(width 0.127)
		(layer "In4.Cu")
		(net "H_CPU1_THERMTRIP_LVC1_R_N")
	)
	(segment
		(start 115.130834 -96.054164)
		(end 118.780052 -92.404946)
		(width 0.127)
		(layer "In4.Cu")
		(net "H_CPU1_THERMTRIP_LVC1_R_N")
	)
	(segment
		(start 61.49467 -179.823618)
		(end 63.67653 -179.823618)
		(width 0.127)
		(layer "In4.Cu")
		(net "H_CPU1_THERMTRIP_LVC1_R_N")
	)
	(segment
		(start 65.4304 -178.069748)
		(end 66.02476 -178.069748)
		(width 0.127)
		(layer "In4.Cu")
		(net "H_CPU1_THERMTRIP_LVC1_R_N")
	)
	(segment
		(start 66.54038 -176.781968)
		(end 68.3768 -174.945548)
		(width 0.127)
		(layer "In4.Cu")
		(net "H_CPU1_THERMTRIP_LVC1_R_N")
	)
	(segment
		(start 68.3768 -174.945548)
		(end 72.263 -174.945548)
		(width 0.127)
		(layer "In4.Cu")
		(net "H_CPU1_THERMTRIP_LVC1_R_N")
	)
	(segment
		(start 115.130834 -97.614994)
		(end 115.130834 -96.054164)
		(width 0.127)
		(layer "In4.Cu")
		(net "H_CPU1_THERMTRIP_LVC1_R_N")
	)
	(segment
		(start 58.4962 -182.822088)
		(end 61.49467 -179.823618)
		(width 0.127)
		(layer "In4.Cu")
		(net "H_CPU1_THERMTRIP_LVC1_R_N")
	)
	(segment
		(start 63.67653 -179.823618)
		(end 65.4304 -178.069748)
		(width 0.127)
		(layer "In4.Cu")
		(net "H_CPU1_THERMTRIP_LVC1_R_N")
	)
	(segment
		(start 72.263 -174.945548)
		(end 74.0918 -173.116748)
		(width 0.127)
		(layer "In4.Cu")
		(net "H_CPU1_THERMTRIP_LVC1_R_N")
	)
	(segment
		(start 74.0918 -173.116748)
		(end 78.417928 -173.116748)
		(width 0.127)
		(layer "In4.Cu")
		(net "H_CPU1_THERMTRIP_LVC1_R_N")
	)
	(segment
		(start 66.54038 -177.554128)
		(end 66.54038 -176.781968)
		(width 0.127)
		(layer "In4.Cu")
		(net "H_CPU1_THERMTRIP_LVC1_R_N")
	)
	(segment
		(start 180.555646 -109.775498)
		(end 180.955696 -109.375448)
		(width 0.12954)
		(layer "F.Cu")
		(net "H_CPU1_THERMTRIP_LVC1_N")
	)
	(segment
		(start 126.67488 -92.274898)
		(end 126.67488 -91.658948)
		(width 0.12954)
		(layer "F.Cu")
		(net "H_CPU1_THERMTRIP_LVC1_N")
	)
	(via
		(at 180.955696 -109.375448)
		(size 0.4572)
		(drill 0.254)
		(layers "F.Cu" "B.Cu")
		(net "H_CPU1_THERMTRIP_LVC1_N")
	)
	(via
		(at 126.67488 -91.658948)
		(size 0.508)
		(drill 0.254)
		(layers "F.Cu" "B.Cu")
		(net "H_CPU1_THERMTRIP_LVC1_N")
	)
	(segment
		(start 175.01108 -100.975668)
		(end 176.4284 -102.392988)
		(width 0.127)
		(layer "In15.Cu")
		(net "H_CPU1_THERMTRIP_LVC1_N")
	)
	(segment
		(start 176.4284 -104.648)
		(end 178.4858 -106.7054)
		(width 0.127)
		(layer "In15.Cu")
		(net "H_CPU1_THERMTRIP_LVC1_N")
	)
	(segment
		(start 136.62152 -91.037918)
		(end 137.917936 -92.334334)
		(width 0.127)
		(layer "In15.Cu")
		(net "H_CPU1_THERMTRIP_LVC1_N")
	)
	(segment
		(start 127.29591 -91.037918)
		(end 136.62152 -91.037918)
		(width 0.127)
		(layer "In15.Cu")
		(net "H_CPU1_THERMTRIP_LVC1_N")
	)
	(segment
		(start 179.6796 -109.375448)
		(end 180.955696 -109.375448)
		(width 0.127)
		(layer "In15.Cu")
		(net "H_CPU1_THERMTRIP_LVC1_N")
	)
	(segment
		(start 147.47494 -100.320348)
		(end 164.9857 -100.320348)
		(width 0.127)
		(layer "In15.Cu")
		(net "H_CPU1_THERMTRIP_LVC1_N")
	)
	(segment
		(start 178.4858 -108.181648)
		(end 179.6796 -109.375448)
		(width 0.127)
		(layer "In15.Cu")
		(net "H_CPU1_THERMTRIP_LVC1_N")
	)
	(segment
		(start 164.9857 -100.320348)
		(end 165.64102 -100.975668)
		(width 0.127)
		(layer "In15.Cu")
		(net "H_CPU1_THERMTRIP_LVC1_N")
	)
	(segment
		(start 126.67488 -91.658948)
		(end 127.29591 -91.037918)
		(width 0.127)
		(layer "In15.Cu")
		(net "H_CPU1_THERMTRIP_LVC1_N")
	)
	(segment
		(start 176.4284 -102.392988)
		(end 176.4284 -104.648)
		(width 0.127)
		(layer "In15.Cu")
		(net "H_CPU1_THERMTRIP_LVC1_N")
	)
	(segment
		(start 165.64102 -100.975668)
		(end 175.01108 -100.975668)
		(width 0.127)
		(layer "In15.Cu")
		(net "H_CPU1_THERMTRIP_LVC1_N")
	)
	(segment
		(start 137.917936 -92.334334)
		(end 139.488926 -92.334334)
		(width 0.127)
		(layer "In15.Cu")
		(net "H_CPU1_THERMTRIP_LVC1_N")
	)
	(segment
		(start 139.488926 -92.334334)
		(end 147.47494 -100.320348)
		(width 0.127)
		(layer "In15.Cu")
		(net "H_CPU1_THERMTRIP_LVC1_N")
	)
	(segment
		(start 178.4858 -106.7054)
		(end 178.4858 -108.181648)
		(width 0.127)
		(layer "In15.Cu")
		(net "H_CPU1_THERMTRIP_LVC1_N")
	)
	(segment
		(start 106.941112 -231.436418)
		(end 106.941366 -231.436164)
		(width 0.12954)
		(layer "F.Cu")
		(net "H_CPU1_RMCA_LVC1_R_N")
	)
	(segment
		(start 106.941366 -231.436164)
		(end 106.941366 -230.900478)
		(width 0.12954)
		(layer "F.Cu")
		(net "H_CPU1_RMCA_LVC1_R_N")
	)
	(via
		(at 106.941366 -230.900478)
		(size 0.4572)
		(drill 0.2032)
		(layers "F.Cu" "B.Cu")
		(net "H_CPU1_RMCA_LVC1_R_N")
	)
	(via
		(at 84.287106 -200.478898)
		(size 0.6604)
		(drill 0.3302)
		(layers "F.Cu" "B.Cu")
		(net "H_CPU1_RMCA_LVC1_R_N")
	)
	(segment
		(start 90.307414 -225.527616)
		(end 90.292682 -225.51898)
		(width 0.0889)
		(layer "B.Cu")
		(net "H_CPU1_RMCA_LVC1_R_N")
	)
	(segment
		(start 89.180416 -225.211894)
		(end 89.180416 -225.193352)
		(width 0.0889)
		(layer "B.Cu")
		(net "H_CPU1_RMCA_LVC1_R_N")
	)
	(segment
		(start 106.941366 -230.900478)
		(end 106.432096 -230.534464)
		(width 0.0889)
		(layer "B.Cu")
		(net "H_CPU1_RMCA_LVC1_R_N")
	)
	(segment
		(start 97.825814 -225.527616)
		(end 97.811082 -225.51898)
		(width 0.0889)
		(layer "B.Cu")
		(net "H_CPU1_RMCA_LVC1_R_N")
	)
	(segment
		(start 100.645214 -225.527616)
		(end 100.630482 -225.51898)
		(width 0.0889)
		(layer "B.Cu")
		(net "H_CPU1_RMCA_LVC1_R_N")
	)
	(segment
		(start 84.969858 -189.07633)
		(end 84.969858 -189.010544)
		(width 0.12954)
		(layer "B.Cu")
		(net "H_CPU1_RMCA_LVC1_R_N")
	)
	(segment
		(start 101.585014 -225.527616)
		(end 101.570282 -225.51898)
		(width 0.0889)
		(layer "B.Cu")
		(net "H_CPU1_RMCA_LVC1_R_N")
	)
	(segment
		(start 98.765614 -225.527616)
		(end 98.750882 -225.51898)
		(width 0.0889)
		(layer "B.Cu")
		(net "H_CPU1_RMCA_LVC1_R_N")
	)
	(segment
		(start 83.458812 -206.37373)
		(end 83.458812 -201.307192)
		(width 0.12954)
		(layer "B.Cu")
		(net "H_CPU1_RMCA_LVC1_R_N")
	)
	(segment
		(start 84.974684 -189.005718)
		(end 84.974684 -188.435742)
		(width 0.12954)
		(layer "B.Cu")
		(net "H_CPU1_RMCA_LVC1_R_N")
	)
	(segment
		(start 84.969858 -189.010544)
		(end 84.974684 -189.005718)
		(width 0.12954)
		(layer "B.Cu")
		(net "H_CPU1_RMCA_LVC1_R_N")
	)
	(segment
		(start 93.126814 -225.527616)
		(end 93.112082 -225.51898)
		(width 0.0889)
		(layer "B.Cu")
		(net "H_CPU1_RMCA_LVC1_R_N")
	)
	(segment
		(start 94.066614 -225.527616)
		(end 94.051882 -225.51898)
		(width 0.0889)
		(layer "B.Cu")
		(net "H_CPU1_RMCA_LVC1_R_N")
	)
	(segment
		(start 103.464868 -227.155502)
		(end 103.455978 -227.150422)
		(width 0.0889)
		(layer "B.Cu")
		(net "H_CPU1_RMCA_LVC1_R_N")
	)
	(segment
		(start 84.725256 -224.603056)
		(end 84.263484 -224.603056)
		(width 0.0889)
		(layer "B.Cu")
		(net "H_CPU1_RMCA_LVC1_R_N")
	)
	(segment
		(start 84.287106 -189.759082)
		(end 84.969858 -189.07633)
		(width 0.12954)
		(layer "B.Cu")
		(net "H_CPU1_RMCA_LVC1_R_N")
	)
	(segment
		(start 84.263484 -224.603056)
		(end 80.571848 -220.91142)
		(width 0.12954)
		(layer "B.Cu")
		(net "H_CPU1_RMCA_LVC1_R_N")
	)
	(segment
		(start 104.874568 -229.597204)
		(end 104.865678 -229.592124)
		(width 0.0889)
		(layer "B.Cu")
		(net "H_CPU1_RMCA_LVC1_R_N")
	)
	(segment
		(start 95.006414 -225.527616)
		(end 94.991682 -225.51898)
		(width 0.0889)
		(layer "B.Cu")
		(net "H_CPU1_RMCA_LVC1_R_N")
	)
	(segment
		(start 103.934768 -227.969318)
		(end 103.925878 -227.964238)
		(width 0.0889)
		(layer "B.Cu")
		(net "H_CPU1_RMCA_LVC1_R_N")
	)
	(segment
		(start 99.705414 -225.527616)
		(end 99.690682 -225.51898)
		(width 0.0889)
		(layer "B.Cu")
		(net "H_CPU1_RMCA_LVC1_R_N")
	)
	(segment
		(start 83.458812 -201.307192)
		(end 84.287106 -200.478898)
		(width 0.12954)
		(layer "B.Cu")
		(net "H_CPU1_RMCA_LVC1_R_N")
	)
	(segment
		(start 106.284268 -230.41102)
		(end 106.275378 -230.40594)
		(width 0.0889)
		(layer "B.Cu")
		(net "H_CPU1_RMCA_LVC1_R_N")
	)
	(segment
		(start 103.747316 -227.64496)
		(end 103.747316 -227.635054)
		(width 0.0889)
		(layer "B.Cu")
		(net "H_CPU1_RMCA_LVC1_R_N")
	)
	(segment
		(start 104.41051 -228.786944)
		(end 104.404414 -228.783388)
		(width 0.0889)
		(layer "B.Cu")
		(net "H_CPU1_RMCA_LVC1_R_N")
	)
	(segment
		(start 95.946214 -225.527616)
		(end 95.931482 -225.51898)
		(width 0.0889)
		(layer "B.Cu")
		(net "H_CPU1_RMCA_LVC1_R_N")
	)
	(segment
		(start 105.820464 -229.60076)
		(end 105.814368 -229.597204)
		(width 0.0889)
		(layer "B.Cu")
		(net "H_CPU1_RMCA_LVC1_R_N")
	)
	(segment
		(start 102.994968 -226.341686)
		(end 102.986078 -226.336606)
		(width 0.0889)
		(layer "B.Cu")
		(net "H_CPU1_RMCA_LVC1_R_N")
	)
	(segment
		(start 84.287106 -200.478898)
		(end 84.287106 -189.759082)
		(width 0.12954)
		(layer "B.Cu")
		(net "H_CPU1_RMCA_LVC1_R_N")
	)
	(segment
		(start 96.886014 -225.527616)
		(end 96.871282 -225.51898)
		(width 0.0889)
		(layer "B.Cu")
		(net "H_CPU1_RMCA_LVC1_R_N")
	)
	(segment
		(start 102.807516 -226.017328)
		(end 102.807516 -226.003104)
		(width 0.0889)
		(layer "B.Cu")
		(net "H_CPU1_RMCA_LVC1_R_N")
	)
	(segment
		(start 80.571848 -209.260694)
		(end 83.458812 -206.37373)
		(width 0.12954)
		(layer "B.Cu")
		(net "H_CPU1_RMCA_LVC1_R_N")
	)
	(segment
		(start 103.001064 -226.345242)
		(end 102.994968 -226.341686)
		(width 0.0889)
		(layer "B.Cu")
		(net "H_CPU1_RMCA_LVC1_R_N")
	)
	(segment
		(start 86.078568 -224.7138)
		(end 86.068154 -224.707704)
		(width 0.0889)
		(layer "B.Cu")
		(net "H_CPU1_RMCA_LVC1_R_N")
	)
	(segment
		(start 104.216962 -228.45903)
		(end 104.216962 -228.436932)
		(width 0.0889)
		(layer "B.Cu")
		(net "H_CPU1_RMCA_LVC1_R_N")
	)
	(segment
		(start 105.263696 -229.588568)
		(end 105.248964 -229.597204)
		(width 0.0889)
		(layer "B.Cu")
		(net "H_CPU1_RMCA_LVC1_R_N")
	)
	(segment
		(start 92.187014 -225.527616)
		(end 92.172282 -225.51898)
		(width 0.0889)
		(layer "B.Cu")
		(net "H_CPU1_RMCA_LVC1_R_N")
	)
	(segment
		(start 80.571848 -220.91142)
		(end 80.571848 -209.260694)
		(width 0.12954)
		(layer "B.Cu")
		(net "H_CPU1_RMCA_LVC1_R_N")
	)
	(segment
		(start 102.524814 -225.527616)
		(end 102.510082 -225.51898)
		(width 0.0889)
		(layer "B.Cu")
		(net "H_CPU1_RMCA_LVC1_R_N")
	)
	(segment
		(start 104.404414 -228.783388)
		(end 104.395524 -228.778308)
		(width 0.0889)
		(layer "B.Cu")
		(net "H_CPU1_RMCA_LVC1_R_N")
	)
	(arc
		(start 99.690682 -225.51898)
		(mid 99.414241 -225.451814)
		(end 99.14001 -225.527616)
		(width 0.0889)
		(layer "B.Cu")
		(net "H_CPU1_RMCA_LVC1_R_N")
	)
	(arc
		(start 85.138514 -224.7138)
		(mid 84.939174 -224.63123)
		(end 84.725256 -224.603056)
		(width 0.0889)
		(layer "B.Cu")
		(net "H_CPU1_RMCA_LVC1_R_N")
	)
	(arc
		(start 89.180416 -225.193352)
		(mid 89.102305 -224.916403)
		(end 88.897968 -224.7138)
		(width 0.0889)
		(layer "B.Cu")
		(net "H_CPU1_RMCA_LVC1_R_N")
	)
	(arc
		(start 101.570282 -225.51898)
		(mid 101.293841 -225.451814)
		(end 101.01961 -225.527616)
		(width 0.0889)
		(layer "B.Cu")
		(net "H_CPU1_RMCA_LVC1_R_N")
	)
	(arc
		(start 97.26041 -225.527616)
		(mid 97.073212 -225.577759)
		(end 96.886014 -225.527616)
		(width 0.0889)
		(layer "B.Cu")
		(net "H_CPU1_RMCA_LVC1_R_N")
	)
	(arc
		(start 98.20021 -225.527616)
		(mid 98.013012 -225.577759)
		(end 97.825814 -225.527616)
		(width 0.0889)
		(layer "B.Cu")
		(net "H_CPU1_RMCA_LVC1_R_N")
	)
	(arc
		(start 91.247214 -225.527616)
		(mid 90.964512 -225.451874)
		(end 90.68181 -225.527616)
		(width 0.0889)
		(layer "B.Cu")
		(net "H_CPU1_RMCA_LVC1_R_N")
	)
	(arc
		(start 102.986078 -226.336606)
		(mid 102.855164 -226.200246)
		(end 102.807516 -226.017328)
		(width 0.0889)
		(layer "B.Cu")
		(net "H_CPU1_RMCA_LVC1_R_N")
	)
	(arc
		(start 94.991682 -225.51898)
		(mid 94.715241 -225.451814)
		(end 94.44101 -225.527616)
		(width 0.0889)
		(layer "B.Cu")
		(net "H_CPU1_RMCA_LVC1_R_N")
	)
	(arc
		(start 90.292682 -225.51898)
		(mid 90.016241 -225.451814)
		(end 89.74201 -225.527616)
		(width 0.0889)
		(layer "B.Cu")
		(net "H_CPU1_RMCA_LVC1_R_N")
	)
	(arc
		(start 96.32061 -225.527616)
		(mid 96.133412 -225.577759)
		(end 95.946214 -225.527616)
		(width 0.0889)
		(layer "B.Cu")
		(net "H_CPU1_RMCA_LVC1_R_N")
	)
	(arc
		(start 106.096816 -230.086662)
		(mid 106.0229 -229.80716)
		(end 105.820464 -229.60076)
		(width 0.0889)
		(layer "B.Cu")
		(net "H_CPU1_RMCA_LVC1_R_N")
	)
	(arc
		(start 89.74201 -225.527616)
		(mid 89.554812 -225.577759)
		(end 89.367614 -225.527616)
		(width 0.0889)
		(layer "B.Cu")
		(net "H_CPU1_RMCA_LVC1_R_N")
	)
	(arc
		(start 89.367614 -225.527616)
		(mid 89.232681 -225.394262)
		(end 89.180416 -225.211894)
		(width 0.0889)
		(layer "B.Cu")
		(net "H_CPU1_RMCA_LVC1_R_N")
	)
	(arc
		(start 88.897968 -224.7138)
		(mid 88.615266 -224.638024)
		(end 88.332564 -224.7138)
		(width 0.0889)
		(layer "B.Cu")
		(net "H_CPU1_RMCA_LVC1_R_N")
	)
	(arc
		(start 92.56141 -225.527616)
		(mid 92.374212 -225.577759)
		(end 92.187014 -225.527616)
		(width 0.0889)
		(layer "B.Cu")
		(net "H_CPU1_RMCA_LVC1_R_N")
	)
	(arc
		(start 103.925878 -227.964238)
		(mid 103.794964 -227.827878)
		(end 103.747316 -227.64496)
		(width 0.0889)
		(layer "B.Cu")
		(net "H_CPU1_RMCA_LVC1_R_N")
	)
	(arc
		(start 105.248964 -229.597204)
		(mid 105.061766 -229.647347)
		(end 104.874568 -229.597204)
		(width 0.0889)
		(layer "B.Cu")
		(net "H_CPU1_RMCA_LVC1_R_N")
	)
	(arc
		(start 96.871282 -225.51898)
		(mid 96.594841 -225.451814)
		(end 96.32061 -225.527616)
		(width 0.0889)
		(layer "B.Cu")
		(net "H_CPU1_RMCA_LVC1_R_N")
	)
	(arc
		(start 101.95941 -225.527616)
		(mid 101.772212 -225.577759)
		(end 101.585014 -225.527616)
		(width 0.0889)
		(layer "B.Cu")
		(net "H_CPU1_RMCA_LVC1_R_N")
	)
	(arc
		(start 92.172282 -225.51898)
		(mid 91.895841 -225.451814)
		(end 91.62161 -225.527616)
		(width 0.0889)
		(layer "B.Cu")
		(net "H_CPU1_RMCA_LVC1_R_N")
	)
	(arc
		(start 104.216962 -228.436932)
		(mid 104.136051 -228.166804)
		(end 103.934768 -227.969318)
		(width 0.0889)
		(layer "B.Cu")
		(net "H_CPU1_RMCA_LVC1_R_N")
	)
	(arc
		(start 106.432096 -230.534464)
		(mid 106.363472 -230.466409)
		(end 106.284268 -230.41102)
		(width 0.0889)
		(layer "B.Cu")
		(net "H_CPU1_RMCA_LVC1_R_N")
	)
	(arc
		(start 91.62161 -225.527616)
		(mid 91.434412 -225.577759)
		(end 91.247214 -225.527616)
		(width 0.0889)
		(layer "B.Cu")
		(net "H_CPU1_RMCA_LVC1_R_N")
	)
	(arc
		(start 104.395524 -228.778308)
		(mid 104.26461 -228.641948)
		(end 104.216962 -228.45903)
		(width 0.0889)
		(layer "B.Cu")
		(net "H_CPU1_RMCA_LVC1_R_N")
	)
	(arc
		(start 95.931482 -225.51898)
		(mid 95.655041 -225.451814)
		(end 95.38081 -225.527616)
		(width 0.0889)
		(layer "B.Cu")
		(net "H_CPU1_RMCA_LVC1_R_N")
	)
	(arc
		(start 85.51291 -224.7138)
		(mid 85.325712 -224.763943)
		(end 85.138514 -224.7138)
		(width 0.0889)
		(layer "B.Cu")
		(net "H_CPU1_RMCA_LVC1_R_N")
	)
	(arc
		(start 103.455978 -227.150422)
		(mid 103.325064 -227.014062)
		(end 103.277416 -226.831144)
		(width 0.0889)
		(layer "B.Cu")
		(net "H_CPU1_RMCA_LVC1_R_N")
	)
	(arc
		(start 94.44101 -225.527616)
		(mid 94.253812 -225.577759)
		(end 94.066614 -225.527616)
		(width 0.0889)
		(layer "B.Cu")
		(net "H_CPU1_RMCA_LVC1_R_N")
	)
	(arc
		(start 103.747316 -227.635054)
		(mid 103.669205 -227.358105)
		(end 103.464868 -227.155502)
		(width 0.0889)
		(layer "B.Cu")
		(net "H_CPU1_RMCA_LVC1_R_N")
	)
	(arc
		(start 94.051882 -225.51898)
		(mid 93.775441 -225.451814)
		(end 93.50121 -225.527616)
		(width 0.0889)
		(layer "B.Cu")
		(net "H_CPU1_RMCA_LVC1_R_N")
	)
	(arc
		(start 86.068154 -224.707704)
		(mid 85.789722 -224.637858)
		(end 85.51291 -224.7138)
		(width 0.0889)
		(layer "B.Cu")
		(net "H_CPU1_RMCA_LVC1_R_N")
	)
	(arc
		(start 86.452964 -224.7138)
		(mid 86.265766 -224.763943)
		(end 86.078568 -224.7138)
		(width 0.0889)
		(layer "B.Cu")
		(net "H_CPU1_RMCA_LVC1_R_N")
	)
	(arc
		(start 101.01961 -225.527616)
		(mid 100.832412 -225.577759)
		(end 100.645214 -225.527616)
		(width 0.0889)
		(layer "B.Cu")
		(net "H_CPU1_RMCA_LVC1_R_N")
	)
	(arc
		(start 100.630482 -225.51898)
		(mid 100.354041 -225.451814)
		(end 100.07981 -225.527616)
		(width 0.0889)
		(layer "B.Cu")
		(net "H_CPU1_RMCA_LVC1_R_N")
	)
	(arc
		(start 104.865678 -229.592124)
		(mid 104.734764 -229.455764)
		(end 104.687116 -229.272846)
		(width 0.0889)
		(layer "B.Cu")
		(net "H_CPU1_RMCA_LVC1_R_N")
	)
	(arc
		(start 93.112082 -225.51898)
		(mid 92.835641 -225.451814)
		(end 92.56141 -225.527616)
		(width 0.0889)
		(layer "B.Cu")
		(net "H_CPU1_RMCA_LVC1_R_N")
	)
	(arc
		(start 102.807516 -226.003104)
		(mid 102.728297 -225.728419)
		(end 102.524814 -225.527616)
		(width 0.0889)
		(layer "B.Cu")
		(net "H_CPU1_RMCA_LVC1_R_N")
	)
	(arc
		(start 95.38081 -225.527616)
		(mid 95.193612 -225.577759)
		(end 95.006414 -225.527616)
		(width 0.0889)
		(layer "B.Cu")
		(net "H_CPU1_RMCA_LVC1_R_N")
	)
	(arc
		(start 87.392764 -224.7138)
		(mid 87.205566 -224.763943)
		(end 87.018368 -224.7138)
		(width 0.0889)
		(layer "B.Cu")
		(net "H_CPU1_RMCA_LVC1_R_N")
	)
	(arc
		(start 88.332564 -224.7138)
		(mid 88.145366 -224.763943)
		(end 87.958168 -224.7138)
		(width 0.0889)
		(layer "B.Cu")
		(net "H_CPU1_RMCA_LVC1_R_N")
	)
	(arc
		(start 105.814368 -229.597204)
		(mid 105.540169 -229.521369)
		(end 105.263696 -229.588568)
		(width 0.0889)
		(layer "B.Cu")
		(net "H_CPU1_RMCA_LVC1_R_N")
	)
	(arc
		(start 93.50121 -225.527616)
		(mid 93.314012 -225.577759)
		(end 93.126814 -225.527616)
		(width 0.0889)
		(layer "B.Cu")
		(net "H_CPU1_RMCA_LVC1_R_N")
	)
	(arc
		(start 99.14001 -225.527616)
		(mid 98.952812 -225.577759)
		(end 98.765614 -225.527616)
		(width 0.0889)
		(layer "B.Cu")
		(net "H_CPU1_RMCA_LVC1_R_N")
	)
	(arc
		(start 106.275378 -230.40594)
		(mid 106.144464 -230.26958)
		(end 106.096816 -230.086662)
		(width 0.0889)
		(layer "B.Cu")
		(net "H_CPU1_RMCA_LVC1_R_N")
	)
	(arc
		(start 104.687116 -229.272846)
		(mid 104.613125 -228.99328)
		(end 104.41051 -228.786944)
		(width 0.0889)
		(layer "B.Cu")
		(net "H_CPU1_RMCA_LVC1_R_N")
	)
	(arc
		(start 103.277416 -226.831144)
		(mid 103.2035 -226.551642)
		(end 103.001064 -226.345242)
		(width 0.0889)
		(layer "B.Cu")
		(net "H_CPU1_RMCA_LVC1_R_N")
	)
	(arc
		(start 97.811082 -225.51898)
		(mid 97.534641 -225.451814)
		(end 97.26041 -225.527616)
		(width 0.0889)
		(layer "B.Cu")
		(net "H_CPU1_RMCA_LVC1_R_N")
	)
	(arc
		(start 90.68181 -225.527616)
		(mid 90.494612 -225.577759)
		(end 90.307414 -225.527616)
		(width 0.0889)
		(layer "B.Cu")
		(net "H_CPU1_RMCA_LVC1_R_N")
	)
	(arc
		(start 100.07981 -225.527616)
		(mid 99.892612 -225.577759)
		(end 99.705414 -225.527616)
		(width 0.0889)
		(layer "B.Cu")
		(net "H_CPU1_RMCA_LVC1_R_N")
	)
	(arc
		(start 87.958168 -224.7138)
		(mid 87.675466 -224.638024)
		(end 87.392764 -224.7138)
		(width 0.0889)
		(layer "B.Cu")
		(net "H_CPU1_RMCA_LVC1_R_N")
	)
	(arc
		(start 102.510082 -225.51898)
		(mid 102.233641 -225.451814)
		(end 101.95941 -225.527616)
		(width 0.0889)
		(layer "B.Cu")
		(net "H_CPU1_RMCA_LVC1_R_N")
	)
	(arc
		(start 87.018368 -224.7138)
		(mid 86.735666 -224.638024)
		(end 86.452964 -224.7138)
		(width 0.0889)
		(layer "B.Cu")
		(net "H_CPU1_RMCA_LVC1_R_N")
	)
	(arc
		(start 98.750882 -225.51898)
		(mid 98.474441 -225.451814)
		(end 98.20021 -225.527616)
		(width 0.0889)
		(layer "B.Cu")
		(net "H_CPU1_RMCA_LVC1_R_N")
	)
	(segment
		(start 151.29256 -123.612148)
		(end 148.11756 -120.437148)
		(width 0.12954)
		(layer "F.Cu")
		(net "H_CPU1_PROCHOT_LVC1_R_N")
	)
	(segment
		(start 148.11756 -120.437148)
		(end 148.11756 -106.289348)
		(width 0.12954)
		(layer "F.Cu")
		(net "H_CPU1_PROCHOT_LVC1_R_N")
	)
	(segment
		(start 144.520666 -129.977134)
		(end 146.131534 -129.977134)
		(width 0.12954)
		(layer "F.Cu")
		(net "H_CPU1_PROCHOT_LVC1_R_N")
	)
	(segment
		(start 153.898092 -100.508816)
		(end 153.898092 -94.737936)
		(width 0.12954)
		(layer "F.Cu")
		(net "H_CPU1_PROCHOT_LVC1_R_N")
	)
	(segment
		(start 148.11756 -106.289348)
		(end 153.898092 -100.508816)
		(width 0.12954)
		(layer "F.Cu")
		(net "H_CPU1_PROCHOT_LVC1_R_N")
	)
	(segment
		(start 143.9418 -135.8519)
		(end 143.9418 -130.556)
		(width 0.12954)
		(layer "F.Cu")
		(net "H_CPU1_PROCHOT_LVC1_R_N")
	)
	(segment
		(start 151.29256 -124.816108)
		(end 151.29256 -123.612148)
		(width 0.12954)
		(layer "F.Cu")
		(net "H_CPU1_PROCHOT_LVC1_R_N")
	)
	(segment
		(start 144.5387 -146.886168)
		(end 144.5387 -136.4488)
		(width 0.12954)
		(layer "F.Cu")
		(net "H_CPU1_PROCHOT_LVC1_R_N")
	)
	(segment
		(start 144.5387 -136.4488)
		(end 143.9418 -135.8519)
		(width 0.12954)
		(layer "F.Cu")
		(net "H_CPU1_PROCHOT_LVC1_R_N")
	)
	(segment
		(start 143.9418 -130.556)
		(end 144.520666 -129.977134)
		(width 0.12954)
		(layer "F.Cu")
		(net "H_CPU1_PROCHOT_LVC1_R_N")
	)
	(segment
		(start 146.131534 -129.977134)
		(end 151.29256 -124.816108)
		(width 0.12954)
		(layer "F.Cu")
		(net "H_CPU1_PROCHOT_LVC1_R_N")
	)
	(segment
		(start 185.355738 -106.575352)
		(end 185.755788 -106.175302)
		(width 0.12954)
		(layer "F.Cu")
		(net "H_CPU1_PROCHOT_LVC1_R_N")
	)
	(via
		(at 153.898092 -94.737936)
		(size 0.508)
		(drill 0.254)
		(layers "F.Cu" "B.Cu")
		(net "H_CPU1_PROCHOT_LVC1_R_N")
	)
	(via
		(at 144.5387 -146.886168)
		(size 0.508)
		(drill 0.254)
		(layers "F.Cu" "B.Cu")
		(net "H_CPU1_PROCHOT_LVC1_R_N")
	)
	(via
		(at 185.755788 -106.175302)
		(size 0.4572)
		(drill 0.254)
		(layers "F.Cu" "B.Cu")
		(net "H_CPU1_PROCHOT_LVC1_R_N")
	)
	(segment
		(start 144.5387 -146.886168)
		(end 142.58036 -148.844508)
		(width 0.12954)
		(layer "B.Cu")
		(net "H_CPU1_PROCHOT_LVC1_R_N")
	)
	(segment
		(start 80.431132 -180.523388)
		(end 80.430624 -180.523388)
		(width 0.12954)
		(layer "B.Cu")
		(net "H_CPU1_PROCHOT_LVC1_R_N")
	)
	(segment
		(start 83.038696 -177.914808)
		(end 80.431132 -180.522372)
		(width 0.12954)
		(layer "B.Cu")
		(net "H_CPU1_PROCHOT_LVC1_R_N")
	)
	(segment
		(start 80.430624 -180.523388)
		(end 80.430624 -183.696102)
		(width 0.12954)
		(layer "B.Cu")
		(net "H_CPU1_PROCHOT_LVC1_R_N")
	)
	(segment
		(start 140.485368 -149.40026)
		(end 109.426756 -149.40026)
		(width 0.12954)
		(layer "B.Cu")
		(net "H_CPU1_PROCHOT_LVC1_R_N")
	)
	(segment
		(start 142.58036 -148.844508)
		(end 141.04112 -148.844508)
		(width 0.12954)
		(layer "B.Cu")
		(net "H_CPU1_PROCHOT_LVC1_R_N")
	)
	(segment
		(start 109.426756 -149.40026)
		(end 83.038696 -175.78832)
		(width 0.12954)
		(layer "B.Cu")
		(net "H_CPU1_PROCHOT_LVC1_R_N")
	)
	(segment
		(start 141.04112 -148.844508)
		(end 140.485368 -149.40026)
		(width 0.12954)
		(layer "B.Cu")
		(net "H_CPU1_PROCHOT_LVC1_R_N")
	)
	(segment
		(start 83.038696 -175.78832)
		(end 83.038696 -177.914808)
		(width 0.12954)
		(layer "B.Cu")
		(net "H_CPU1_PROCHOT_LVC1_R_N")
	)
	(segment
		(start 80.431132 -180.522372)
		(end 80.431132 -180.523388)
		(width 0.12954)
		(layer "B.Cu")
		(net "H_CPU1_PROCHOT_LVC1_R_N")
	)
	(segment
		(start 181.84368 -96.982788)
		(end 181.84368 -96.114108)
		(width 0.127)
		(layer "In15.Cu")
		(net "H_CPU1_PROCHOT_LVC1_R_N")
	)
	(segment
		(start 185.0644 -101.041454)
		(end 184.141364 -98.813112)
		(width 0.127)
		(layer "In15.Cu")
		(net "H_CPU1_PROCHOT_LVC1_R_N")
	)
	(segment
		(start 180.53812 -94.808548)
		(end 179.8574 -94.808548)
		(width 0.127)
		(layer "In15.Cu")
		(net "H_CPU1_PROCHOT_LVC1_R_N")
	)
	(segment
		(start 171.59224 -93.856048)
		(end 154.77998 -93.856048)
		(width 0.127)
		(layer "In15.Cu")
		(net "H_CPU1_PROCHOT_LVC1_R_N")
	)
	(segment
		(start 154.77998 -93.856048)
		(end 153.898092 -94.737936)
		(width 0.127)
		(layer "In15.Cu")
		(net "H_CPU1_PROCHOT_LVC1_R_N")
	)
	(segment
		(start 185.755788 -106.175302)
		(end 185.0644 -105.483914)
		(width 0.127)
		(layer "In15.Cu")
		(net "H_CPU1_PROCHOT_LVC1_R_N")
	)
	(segment
		(start 178.05146 -93.002608)
		(end 172.44568 -93.002608)
		(width 0.127)
		(layer "In15.Cu")
		(net "H_CPU1_PROCHOT_LVC1_R_N")
	)
	(segment
		(start 172.44568 -93.002608)
		(end 171.59224 -93.856048)
		(width 0.127)
		(layer "In15.Cu")
		(net "H_CPU1_PROCHOT_LVC1_R_N")
	)
	(segment
		(start 182.88762 -97.559368)
		(end 182.42026 -97.559368)
		(width 0.127)
		(layer "In15.Cu")
		(net "H_CPU1_PROCHOT_LVC1_R_N")
	)
	(segment
		(start 182.42026 -97.559368)
		(end 181.84368 -96.982788)
		(width 0.127)
		(layer "In15.Cu")
		(net "H_CPU1_PROCHOT_LVC1_R_N")
	)
	(segment
		(start 185.0644 -105.483914)
		(end 185.0644 -101.041454)
		(width 0.127)
		(layer "In15.Cu")
		(net "H_CPU1_PROCHOT_LVC1_R_N")
	)
	(segment
		(start 184.141364 -98.813112)
		(end 182.88762 -97.559368)
		(width 0.127)
		(layer "In15.Cu")
		(net "H_CPU1_PROCHOT_LVC1_R_N")
	)
	(segment
		(start 181.84368 -96.114108)
		(end 180.53812 -94.808548)
		(width 0.127)
		(layer "In15.Cu")
		(net "H_CPU1_PROCHOT_LVC1_R_N")
	)
	(segment
		(start 179.8574 -94.808548)
		(end 178.05146 -93.002608)
		(width 0.127)
		(layer "In15.Cu")
		(net "H_CPU1_PROCHOT_LVC1_R_N")
	)
	(segment
		(start 101.772466 -228.99497)
		(end 101.772466 -228.459284)
		(width 0.12954)
		(layer "F.Cu")
		(net "H_CPU1_PROCHOT_LVC1_N")
	)
	(segment
		(start 101.772466 -228.459284)
		(end 101.772212 -228.45903)
		(width 0.12954)
		(layer "F.Cu")
		(net "H_CPU1_PROCHOT_LVC1_N")
	)
	(via
		(at 101.772212 -228.45903)
		(size 0.4572)
		(drill 0.2032)
		(layers "F.Cu" "B.Cu")
		(net "H_CPU1_PROCHOT_LVC1_N")
	)
	(via
		(at 77.98562 -205.104746)
		(size 0.6604)
		(drill 0.3302)
		(layers "F.Cu" "B.Cu")
		(net "H_CPU1_PROCHOT_LVC1_N")
	)
	(segment
		(start 83.363308 -228.210618)
		(end 82.668618 -228.210618)
		(width 0.12954)
		(layer "B.Cu")
		(net "H_CPU1_PROCHOT_LVC1_N")
	)
	(segment
		(start 97.826068 -228.134672)
		(end 97.815654 -228.140768)
		(width 0.0889)
		(layer "B.Cu")
		(net "H_CPU1_PROCHOT_LVC1_N")
	)
	(segment
		(start 79.630778 -185.682636)
		(end 79.839312 -185.474102)
		(width 0.12954)
		(layer "B.Cu")
		(net "H_CPU1_PROCHOT_LVC1_N")
	)
	(segment
		(start 79.748634 -196.55282)
		(end 80.151478 -196.149976)
		(width 0.12954)
		(layer "B.Cu")
		(net "H_CPU1_PROCHOT_LVC1_N")
	)
	(segment
		(start 79.630778 -187.708286)
		(end 79.630778 -185.682636)
		(width 0.12954)
		(layer "B.Cu")
		(net "H_CPU1_PROCHOT_LVC1_N")
	)
	(segment
		(start 87.473536 -228.1428)
		(end 87.35695 -228.210618)
		(width 0.0889)
		(layer "B.Cu")
		(net "H_CPU1_PROCHOT_LVC1_N")
	)
	(segment
		(start 90.307414 -228.134672)
		(end 90.292682 -228.143308)
		(width 0.0889)
		(layer "B.Cu")
		(net "H_CPU1_PROCHOT_LVC1_N")
	)
	(segment
		(start 77.98562 -205.104746)
		(end 79.748634 -203.341732)
		(width 0.12954)
		(layer "B.Cu")
		(net "H_CPU1_PROCHOT_LVC1_N")
	)
	(segment
		(start 77.203808 -205.886558)
		(end 77.98562 -205.104746)
		(width 0.12954)
		(layer "B.Cu")
		(net "H_CPU1_PROCHOT_LVC1_N")
	)
	(segment
		(start 80.430624 -184.496202)
		(end 80.430624 -185.474102)
		(width 0.12954)
		(layer "B.Cu")
		(net "H_CPU1_PROCHOT_LVC1_N")
	)
	(segment
		(start 79.748634 -203.341732)
		(end 79.748634 -196.55282)
		(width 0.12954)
		(layer "B.Cu")
		(net "H_CPU1_PROCHOT_LVC1_N")
	)
	(segment
		(start 101.772212 -228.45903)
		(end 101.928676 -228.188012)
		(width 0.0889)
		(layer "B.Cu")
		(net "H_CPU1_PROCHOT_LVC1_N")
	)
	(segment
		(start 79.839312 -185.474102)
		(end 80.430624 -185.474102)
		(width 0.12954)
		(layer "B.Cu")
		(net "H_CPU1_PROCHOT_LVC1_N")
	)
	(segment
		(start 91.247468 -228.134672)
		(end 91.237054 -228.140768)
		(width 0.0889)
		(layer "B.Cu")
		(net "H_CPU1_PROCHOT_LVC1_N")
	)
	(segment
		(start 77.203808 -222.745808)
		(end 77.203808 -205.886558)
		(width 0.12954)
		(layer "B.Cu")
		(net "H_CPU1_PROCHOT_LVC1_N")
	)
	(segment
		(start 87.488268 -228.134672)
		(end 87.475822 -228.14153)
		(width 0.0889)
		(layer "B.Cu")
		(net "H_CPU1_PROCHOT_LVC1_N")
	)
	(segment
		(start 95.946214 -228.134672)
		(end 95.931482 -228.143308)
		(width 0.0889)
		(layer "B.Cu")
		(net "H_CPU1_PROCHOT_LVC1_N")
	)
	(segment
		(start 98.765614 -228.134672)
		(end 98.7552 -228.140768)
		(width 0.0889)
		(layer "B.Cu")
		(net "H_CPU1_PROCHOT_LVC1_N")
	)
	(segment
		(start 100.645214 -228.134672)
		(end 100.630482 -228.143308)
		(width 0.0889)
		(layer "B.Cu")
		(net "H_CPU1_PROCHOT_LVC1_N")
	)
	(segment
		(start 96.886014 -228.134672)
		(end 96.871282 -228.143308)
		(width 0.0889)
		(layer "B.Cu")
		(net "H_CPU1_PROCHOT_LVC1_N")
	)
	(segment
		(start 89.367614 -228.134672)
		(end 89.352882 -228.143308)
		(width 0.0889)
		(layer "B.Cu")
		(net "H_CPU1_PROCHOT_LVC1_N")
	)
	(segment
		(start 91.632278 -228.140768)
		(end 91.621864 -228.134672)
		(width 0.0889)
		(layer "B.Cu")
		(net "H_CPU1_PROCHOT_LVC1_N")
	)
	(segment
		(start 93.126814 -228.134672)
		(end 93.112082 -228.143308)
		(width 0.0889)
		(layer "B.Cu")
		(net "H_CPU1_PROCHOT_LVC1_N")
	)
	(segment
		(start 87.35695 -228.210618)
		(end 83.363308 -228.210618)
		(width 0.0889)
		(layer "B.Cu")
		(net "H_CPU1_PROCHOT_LVC1_N")
	)
	(segment
		(start 95.006414 -228.134672)
		(end 94.991682 -228.143308)
		(width 0.0889)
		(layer "B.Cu")
		(net "H_CPU1_PROCHOT_LVC1_N")
	)
	(segment
		(start 82.668618 -228.210618)
		(end 77.203808 -222.745808)
		(width 0.12954)
		(layer "B.Cu")
		(net "H_CPU1_PROCHOT_LVC1_N")
	)
	(segment
		(start 94.066614 -228.134672)
		(end 94.051882 -228.143308)
		(width 0.0889)
		(layer "B.Cu")
		(net "H_CPU1_PROCHOT_LVC1_N")
	)
	(segment
		(start 87.475822 -228.14153)
		(end 87.473536 -228.1428)
		(width 0.0889)
		(layer "B.Cu")
		(net "H_CPU1_PROCHOT_LVC1_N")
	)
	(segment
		(start 80.151478 -188.965586)
		(end 79.630778 -187.708286)
		(width 0.12954)
		(layer "B.Cu")
		(net "H_CPU1_PROCHOT_LVC1_N")
	)
	(segment
		(start 80.151478 -196.149976)
		(end 80.151478 -188.965586)
		(width 0.12954)
		(layer "B.Cu")
		(net "H_CPU1_PROCHOT_LVC1_N")
	)
	(segment
		(start 88.427814 -228.134672)
		(end 88.4174 -228.140768)
		(width 0.0889)
		(layer "B.Cu")
		(net "H_CPU1_PROCHOT_LVC1_N")
	)
	(segment
		(start 101.585014 -228.134672)
		(end 101.570282 -228.143308)
		(width 0.0889)
		(layer "B.Cu")
		(net "H_CPU1_PROCHOT_LVC1_N")
	)
	(segment
		(start 101.928676 -228.188012)
		(end 101.907594 -228.110034)
		(width 0.0889)
		(layer "B.Cu")
		(net "H_CPU1_PROCHOT_LVC1_N")
	)
	(arc
		(start 101.907594 -228.110034)
		(mid 101.743498 -228.085687)
		(end 101.585014 -228.134672)
		(width 0.0889)
		(layer "B.Cu")
		(net "H_CPU1_PROCHOT_LVC1_N")
	)
	(arc
		(start 100.07981 -228.134672)
		(mid 99.892612 -228.084529)
		(end 99.705414 -228.134672)
		(width 0.0889)
		(layer "B.Cu")
		(net "H_CPU1_PROCHOT_LVC1_N")
	)
	(arc
		(start 93.50121 -228.134672)
		(mid 93.314012 -228.084529)
		(end 93.126814 -228.134672)
		(width 0.0889)
		(layer "B.Cu")
		(net "H_CPU1_PROCHOT_LVC1_N")
	)
	(arc
		(start 90.68181 -228.134672)
		(mid 90.494612 -228.084529)
		(end 90.307414 -228.134672)
		(width 0.0889)
		(layer "B.Cu")
		(net "H_CPU1_PROCHOT_LVC1_N")
	)
	(arc
		(start 97.815654 -228.140768)
		(mid 97.537222 -228.210582)
		(end 97.26041 -228.134672)
		(width 0.0889)
		(layer "B.Cu")
		(net "H_CPU1_PROCHOT_LVC1_N")
	)
	(arc
		(start 101.01961 -228.134672)
		(mid 100.832412 -228.084529)
		(end 100.645214 -228.134672)
		(width 0.0889)
		(layer "B.Cu")
		(net "H_CPU1_PROCHOT_LVC1_N")
	)
	(arc
		(start 88.4174 -228.140768)
		(mid 88.139222 -228.21046)
		(end 87.862664 -228.134672)
		(width 0.0889)
		(layer "B.Cu")
		(net "H_CPU1_PROCHOT_LVC1_N")
	)
	(arc
		(start 89.74201 -228.134672)
		(mid 89.554812 -228.084529)
		(end 89.367614 -228.134672)
		(width 0.0889)
		(layer "B.Cu")
		(net "H_CPU1_PROCHOT_LVC1_N")
	)
	(arc
		(start 95.931482 -228.143308)
		(mid 95.655041 -228.210474)
		(end 95.38081 -228.134672)
		(width 0.0889)
		(layer "B.Cu")
		(net "H_CPU1_PROCHOT_LVC1_N")
	)
	(arc
		(start 90.292682 -228.143308)
		(mid 90.016241 -228.210474)
		(end 89.74201 -228.134672)
		(width 0.0889)
		(layer "B.Cu")
		(net "H_CPU1_PROCHOT_LVC1_N")
	)
	(arc
		(start 99.14001 -228.134672)
		(mid 98.952812 -228.084529)
		(end 98.765614 -228.134672)
		(width 0.0889)
		(layer "B.Cu")
		(net "H_CPU1_PROCHOT_LVC1_N")
	)
	(arc
		(start 99.705414 -228.134672)
		(mid 99.422712 -228.210414)
		(end 99.14001 -228.134672)
		(width 0.0889)
		(layer "B.Cu")
		(net "H_CPU1_PROCHOT_LVC1_N")
	)
	(arc
		(start 97.26041 -228.134672)
		(mid 97.073212 -228.084529)
		(end 96.886014 -228.134672)
		(width 0.0889)
		(layer "B.Cu")
		(net "H_CPU1_PROCHOT_LVC1_N")
	)
	(arc
		(start 98.7552 -228.140768)
		(mid 98.477022 -228.21046)
		(end 98.200464 -228.134672)
		(width 0.0889)
		(layer "B.Cu")
		(net "H_CPU1_PROCHOT_LVC1_N")
	)
	(arc
		(start 92.56141 -228.134672)
		(mid 92.374212 -228.084529)
		(end 92.187014 -228.134672)
		(width 0.0889)
		(layer "B.Cu")
		(net "H_CPU1_PROCHOT_LVC1_N")
	)
	(arc
		(start 87.862664 -228.134672)
		(mid 87.675466 -228.084529)
		(end 87.488268 -228.134672)
		(width 0.0889)
		(layer "B.Cu")
		(net "H_CPU1_PROCHOT_LVC1_N")
	)
	(arc
		(start 92.187014 -228.134672)
		(mid 91.910455 -228.210381)
		(end 91.632278 -228.140768)
		(width 0.0889)
		(layer "B.Cu")
		(net "H_CPU1_PROCHOT_LVC1_N")
	)
	(arc
		(start 88.80221 -228.134672)
		(mid 88.615012 -228.084529)
		(end 88.427814 -228.134672)
		(width 0.0889)
		(layer "B.Cu")
		(net "H_CPU1_PROCHOT_LVC1_N")
	)
	(arc
		(start 89.352882 -228.143308)
		(mid 89.076441 -228.210474)
		(end 88.80221 -228.134672)
		(width 0.0889)
		(layer "B.Cu")
		(net "H_CPU1_PROCHOT_LVC1_N")
	)
	(arc
		(start 94.991682 -228.143308)
		(mid 94.715241 -228.210474)
		(end 94.44101 -228.134672)
		(width 0.0889)
		(layer "B.Cu")
		(net "H_CPU1_PROCHOT_LVC1_N")
	)
	(arc
		(start 96.32061 -228.134672)
		(mid 96.133412 -228.084529)
		(end 95.946214 -228.134672)
		(width 0.0889)
		(layer "B.Cu")
		(net "H_CPU1_PROCHOT_LVC1_N")
	)
	(arc
		(start 95.38081 -228.134672)
		(mid 95.193612 -228.084529)
		(end 95.006414 -228.134672)
		(width 0.0889)
		(layer "B.Cu")
		(net "H_CPU1_PROCHOT_LVC1_N")
	)
	(arc
		(start 94.051882 -228.143308)
		(mid 93.775441 -228.210474)
		(end 93.50121 -228.134672)
		(width 0.0889)
		(layer "B.Cu")
		(net "H_CPU1_PROCHOT_LVC1_N")
	)
	(arc
		(start 91.237054 -228.140768)
		(mid 90.958622 -228.210582)
		(end 90.68181 -228.134672)
		(width 0.0889)
		(layer "B.Cu")
		(net "H_CPU1_PROCHOT_LVC1_N")
	)
	(arc
		(start 94.44101 -228.134672)
		(mid 94.253812 -228.084529)
		(end 94.066614 -228.134672)
		(width 0.0889)
		(layer "B.Cu")
		(net "H_CPU1_PROCHOT_LVC1_N")
	)
	(arc
		(start 101.570282 -228.143308)
		(mid 101.293841 -228.210474)
		(end 101.01961 -228.134672)
		(width 0.0889)
		(layer "B.Cu")
		(net "H_CPU1_PROCHOT_LVC1_N")
	)
	(arc
		(start 100.630482 -228.143308)
		(mid 100.354041 -228.210474)
		(end 100.07981 -228.134672)
		(width 0.0889)
		(layer "B.Cu")
		(net "H_CPU1_PROCHOT_LVC1_N")
	)
	(arc
		(start 98.200464 -228.134672)
		(mid 98.013266 -228.084529)
		(end 97.826068 -228.134672)
		(width 0.0889)
		(layer "B.Cu")
		(net "H_CPU1_PROCHOT_LVC1_N")
	)
	(arc
		(start 93.112082 -228.143308)
		(mid 92.835641 -228.210474)
		(end 92.56141 -228.134672)
		(width 0.0889)
		(layer "B.Cu")
		(net "H_CPU1_PROCHOT_LVC1_N")
	)
	(arc
		(start 96.871282 -228.143308)
		(mid 96.594841 -228.210474)
		(end 96.32061 -228.134672)
		(width 0.0889)
		(layer "B.Cu")
		(net "H_CPU1_PROCHOT_LVC1_N")
	)
	(arc
		(start 91.621864 -228.134672)
		(mid 91.434666 -228.084529)
		(end 91.247468 -228.134672)
		(width 0.0889)
		(layer "B.Cu")
		(net "H_CPU1_PROCHOT_LVC1_N")
	)
	(segment
		(start 102.242112 -230.900732)
		(end 102.242366 -230.900478)
		(width 0.12954)
		(layer "F.Cu")
		(net "H_CPU1_PREQ_QS_GTL_R_N")
	)
	(segment
		(start 102.242112 -231.436418)
		(end 102.242112 -230.900732)
		(width 0.12954)
		(layer "F.Cu")
		(net "H_CPU1_PREQ_QS_GTL_R_N")
	)
	(via
		(at 75.742038 -199.66178)
		(size 0.6604)
		(drill 0.3302)
		(layers "F.Cu" "B.Cu")
		(net "H_CPU1_PREQ_QS_GTL_R_N")
	)
	(via
		(at 102.242366 -230.900478)
		(size 0.4572)
		(drill 0.2032)
		(layers "F.Cu" "B.Cu")
		(net "H_CPU1_PREQ_QS_GTL_R_N")
	)
	(segment
		(start 84.212684 -230.749856)
		(end 83.56473 -231.39781)
		(width 0.0889)
		(layer "B.Cu")
		(net "H_CPU1_PREQ_QS_GTL_R_N")
	)
	(segment
		(start 89.287096 -230.584756)
		(end 89.272364 -230.57612)
		(width 0.0889)
		(layer "B.Cu")
		(net "H_CPU1_PREQ_QS_GTL_R_N")
	)
	(segment
		(start 88.145366 -230.525574)
		(end 87.94877 -230.525574)
		(width 0.0889)
		(layer "B.Cu")
		(net "H_CPU1_PREQ_QS_GTL_R_N")
	)
	(segment
		(start 102.085902 -230.62946)
		(end 101.996748 -230.605584)
		(width 0.0889)
		(layer "B.Cu")
		(net "H_CPU1_PREQ_QS_GTL_R_N")
	)
	(segment
		(start 75.742038 -196.363844)
		(end 77.214222 -194.89166)
		(width 0.12954)
		(layer "B.Cu")
		(net "H_CPU1_PREQ_QS_GTL_R_N")
	)
	(segment
		(start 98.685096 -230.584756)
		(end 98.678238 -230.580692)
		(width 0.0889)
		(layer "B.Cu")
		(net "H_CPU1_PREQ_QS_GTL_R_N")
	)
	(segment
		(start 97.355914 -230.57612)
		(end 97.3455 -230.582216)
		(width 0.0889)
		(layer "B.Cu")
		(net "H_CPU1_PREQ_QS_GTL_R_N")
	)
	(segment
		(start 83.56473 -231.39781)
		(end 80.408018 -231.39781)
		(width 0.12954)
		(layer "B.Cu")
		(net "H_CPU1_PREQ_QS_GTL_R_N")
	)
	(segment
		(start 102.242366 -230.900478)
		(end 102.085902 -230.62946)
		(width 0.0889)
		(layer "B.Cu")
		(net "H_CPU1_PREQ_QS_GTL_R_N")
	)
	(segment
		(start 93.986096 -230.584756)
		(end 93.971364 -230.57612)
		(width 0.0889)
		(layer "B.Cu")
		(net "H_CPU1_PREQ_QS_GTL_R_N")
	)
	(segment
		(start 88.347296 -230.584756)
		(end 88.332564 -230.57612)
		(width 0.0889)
		(layer "B.Cu")
		(net "H_CPU1_PREQ_QS_GTL_R_N")
	)
	(segment
		(start 75.742038 -199.66178)
		(end 75.742038 -196.363844)
		(width 0.12954)
		(layer "B.Cu")
		(net "H_CPU1_PREQ_QS_GTL_R_N")
	)
	(segment
		(start 76.056998 -184.277)
		(end 76.463652 -183.870346)
		(width 0.12954)
		(layer "B.Cu")
		(net "H_CPU1_PREQ_QS_GTL_R_N")
	)
	(segment
		(start 100.564696 -230.584756)
		(end 100.549964 -230.57612)
		(width 0.0889)
		(layer "B.Cu")
		(net "H_CPU1_PREQ_QS_GTL_R_N")
	)
	(segment
		(start 93.046296 -230.584756)
		(end 93.031564 -230.57612)
		(width 0.0889)
		(layer "B.Cu")
		(net "H_CPU1_PREQ_QS_GTL_R_N")
	)
	(segment
		(start 77.214222 -189.771274)
		(end 76.056998 -186.976258)
		(width 0.12954)
		(layer "B.Cu")
		(net "H_CPU1_PREQ_QS_GTL_R_N")
	)
	(segment
		(start 94.925896 -230.584756)
		(end 94.911164 -230.57612)
		(width 0.0889)
		(layer "B.Cu")
		(net "H_CPU1_PREQ_QS_GTL_R_N")
	)
	(segment
		(start 98.678238 -230.580692)
		(end 98.670364 -230.57612)
		(width 0.0889)
		(layer "B.Cu")
		(net "H_CPU1_PREQ_QS_GTL_R_N")
	)
	(segment
		(start 80.408018 -231.39781)
		(end 73.683368 -224.67316)
		(width 0.12954)
		(layer "B.Cu")
		(net "H_CPU1_PREQ_QS_GTL_R_N")
	)
	(segment
		(start 87.724488 -230.749856)
		(end 84.212684 -230.749856)
		(width 0.0889)
		(layer "B.Cu")
		(net "H_CPU1_PREQ_QS_GTL_R_N")
	)
	(segment
		(start 90.777314 -230.57612)
		(end 90.7669 -230.582216)
		(width 0.0889)
		(layer "B.Cu")
		(net "H_CPU1_PREQ_QS_GTL_R_N")
	)
	(segment
		(start 92.106496 -230.584756)
		(end 92.091764 -230.57612)
		(width 0.0889)
		(layer "B.Cu")
		(net "H_CPU1_PREQ_QS_GTL_R_N")
	)
	(segment
		(start 76.056998 -186.976258)
		(end 76.056998 -184.277)
		(width 0.12954)
		(layer "B.Cu")
		(net "H_CPU1_PREQ_QS_GTL_R_N")
	)
	(segment
		(start 95.865696 -230.584756)
		(end 95.850964 -230.57612)
		(width 0.0889)
		(layer "B.Cu")
		(net "H_CPU1_PREQ_QS_GTL_R_N")
	)
	(segment
		(start 97.740724 -230.582216)
		(end 97.73031 -230.57612)
		(width 0.0889)
		(layer "B.Cu")
		(net "H_CPU1_PREQ_QS_GTL_R_N")
	)
	(segment
		(start 77.214222 -194.89166)
		(end 77.214222 -189.771274)
		(width 0.12954)
		(layer "B.Cu")
		(net "H_CPU1_PREQ_QS_GTL_R_N")
	)
	(segment
		(start 91.162124 -230.582216)
		(end 91.15171 -230.57612)
		(width 0.0889)
		(layer "B.Cu")
		(net "H_CPU1_PREQ_QS_GTL_R_N")
	)
	(segment
		(start 73.683368 -203.283566)
		(end 75.742038 -201.224896)
		(width 0.12954)
		(layer "B.Cu")
		(net "H_CPU1_PREQ_QS_GTL_R_N")
	)
	(segment
		(start 99.624896 -230.584756)
		(end 99.610164 -230.57612)
		(width 0.0889)
		(layer "B.Cu")
		(net "H_CPU1_PREQ_QS_GTL_R_N")
	)
	(segment
		(start 87.94877 -230.525574)
		(end 87.724488 -230.749856)
		(width 0.0889)
		(layer "B.Cu")
		(net "H_CPU1_PREQ_QS_GTL_R_N")
	)
	(segment
		(start 101.504496 -230.584756)
		(end 101.489764 -230.57612)
		(width 0.0889)
		(layer "B.Cu")
		(net "H_CPU1_PREQ_QS_GTL_R_N")
	)
	(segment
		(start 75.742038 -201.224896)
		(end 75.742038 -199.66178)
		(width 0.12954)
		(layer "B.Cu")
		(net "H_CPU1_PREQ_QS_GTL_R_N")
	)
	(segment
		(start 73.683368 -224.67316)
		(end 73.683368 -203.283566)
		(width 0.12954)
		(layer "B.Cu")
		(net "H_CPU1_PREQ_QS_GTL_R_N")
	)
	(arc
		(start 88.897968 -230.57612)
		(mid 88.623769 -230.651955)
		(end 88.347296 -230.584756)
		(width 0.0889)
		(layer "B.Cu")
		(net "H_CPU1_PREQ_QS_GTL_R_N")
	)
	(arc
		(start 88.332564 -230.57612)
		(mid 88.242292 -230.538521)
		(end 88.145366 -230.525574)
		(width 0.0889)
		(layer "B.Cu")
		(net "H_CPU1_PREQ_QS_GTL_R_N")
	)
	(arc
		(start 95.476568 -230.57612)
		(mid 95.202369 -230.651955)
		(end 94.925896 -230.584756)
		(width 0.0889)
		(layer "B.Cu")
		(net "H_CPU1_PREQ_QS_GTL_R_N")
	)
	(arc
		(start 94.536768 -230.57612)
		(mid 94.262569 -230.651955)
		(end 93.986096 -230.584756)
		(width 0.0889)
		(layer "B.Cu")
		(net "H_CPU1_PREQ_QS_GTL_R_N")
	)
	(arc
		(start 96.790764 -230.57612)
		(mid 96.603566 -230.525977)
		(end 96.416368 -230.57612)
		(width 0.0889)
		(layer "B.Cu")
		(net "H_CPU1_PREQ_QS_GTL_R_N")
	)
	(arc
		(start 93.031564 -230.57612)
		(mid 92.844366 -230.525977)
		(end 92.657168 -230.57612)
		(width 0.0889)
		(layer "B.Cu")
		(net "H_CPU1_PREQ_QS_GTL_R_N")
	)
	(arc
		(start 93.596968 -230.57612)
		(mid 93.322769 -230.651955)
		(end 93.046296 -230.584756)
		(width 0.0889)
		(layer "B.Cu")
		(net "H_CPU1_PREQ_QS_GTL_R_N")
	)
	(arc
		(start 89.837768 -230.57612)
		(mid 89.563569 -230.651955)
		(end 89.287096 -230.584756)
		(width 0.0889)
		(layer "B.Cu")
		(net "H_CPU1_PREQ_QS_GTL_R_N")
	)
	(arc
		(start 94.911164 -230.57612)
		(mid 94.723966 -230.525977)
		(end 94.536768 -230.57612)
		(width 0.0889)
		(layer "B.Cu")
		(net "H_CPU1_PREQ_QS_GTL_R_N")
	)
	(arc
		(start 96.416368 -230.57612)
		(mid 96.142169 -230.651955)
		(end 95.865696 -230.584756)
		(width 0.0889)
		(layer "B.Cu")
		(net "H_CPU1_PREQ_QS_GTL_R_N")
	)
	(arc
		(start 99.235768 -230.57612)
		(mid 98.961569 -230.651955)
		(end 98.685096 -230.584756)
		(width 0.0889)
		(layer "B.Cu")
		(net "H_CPU1_PREQ_QS_GTL_R_N")
	)
	(arc
		(start 100.175568 -230.57612)
		(mid 99.901369 -230.651955)
		(end 99.624896 -230.584756)
		(width 0.0889)
		(layer "B.Cu")
		(net "H_CPU1_PREQ_QS_GTL_R_N")
	)
	(arc
		(start 101.489764 -230.57612)
		(mid 101.302566 -230.525977)
		(end 101.115368 -230.57612)
		(width 0.0889)
		(layer "B.Cu")
		(net "H_CPU1_PREQ_QS_GTL_R_N")
	)
	(arc
		(start 98.295968 -230.57612)
		(mid 98.019155 -230.65199)
		(end 97.740724 -230.582216)
		(width 0.0889)
		(layer "B.Cu")
		(net "H_CPU1_PREQ_QS_GTL_R_N")
	)
	(arc
		(start 95.850964 -230.57612)
		(mid 95.663766 -230.525977)
		(end 95.476568 -230.57612)
		(width 0.0889)
		(layer "B.Cu")
		(net "H_CPU1_PREQ_QS_GTL_R_N")
	)
	(arc
		(start 89.272364 -230.57612)
		(mid 89.085166 -230.525977)
		(end 88.897968 -230.57612)
		(width 0.0889)
		(layer "B.Cu")
		(net "H_CPU1_PREQ_QS_GTL_R_N")
	)
	(arc
		(start 97.3455 -230.582216)
		(mid 97.067322 -230.651939)
		(end 96.790764 -230.57612)
		(width 0.0889)
		(layer "B.Cu")
		(net "H_CPU1_PREQ_QS_GTL_R_N")
	)
	(arc
		(start 90.7669 -230.582216)
		(mid 90.488722 -230.651939)
		(end 90.212164 -230.57612)
		(width 0.0889)
		(layer "B.Cu")
		(net "H_CPU1_PREQ_QS_GTL_R_N")
	)
	(arc
		(start 101.996748 -230.605584)
		(mid 101.748243 -230.651571)
		(end 101.504496 -230.584756)
		(width 0.0889)
		(layer "B.Cu")
		(net "H_CPU1_PREQ_QS_GTL_R_N")
	)
	(arc
		(start 92.091764 -230.57612)
		(mid 91.904566 -230.525977)
		(end 91.717368 -230.57612)
		(width 0.0889)
		(layer "B.Cu")
		(net "H_CPU1_PREQ_QS_GTL_R_N")
	)
	(arc
		(start 90.212164 -230.57612)
		(mid 90.024966 -230.525977)
		(end 89.837768 -230.57612)
		(width 0.0889)
		(layer "B.Cu")
		(net "H_CPU1_PREQ_QS_GTL_R_N")
	)
	(arc
		(start 101.115368 -230.57612)
		(mid 100.841169 -230.651955)
		(end 100.564696 -230.584756)
		(width 0.0889)
		(layer "B.Cu")
		(net "H_CPU1_PREQ_QS_GTL_R_N")
	)
	(arc
		(start 98.670364 -230.57612)
		(mid 98.483166 -230.525977)
		(end 98.295968 -230.57612)
		(width 0.0889)
		(layer "B.Cu")
		(net "H_CPU1_PREQ_QS_GTL_R_N")
	)
	(arc
		(start 91.15171 -230.57612)
		(mid 90.964512 -230.525977)
		(end 90.777314 -230.57612)
		(width 0.0889)
		(layer "B.Cu")
		(net "H_CPU1_PREQ_QS_GTL_R_N")
	)
	(arc
		(start 93.971364 -230.57612)
		(mid 93.784166 -230.525977)
		(end 93.596968 -230.57612)
		(width 0.0889)
		(layer "B.Cu")
		(net "H_CPU1_PREQ_QS_GTL_R_N")
	)
	(arc
		(start 97.73031 -230.57612)
		(mid 97.543112 -230.525977)
		(end 97.355914 -230.57612)
		(width 0.0889)
		(layer "B.Cu")
		(net "H_CPU1_PREQ_QS_GTL_R_N")
	)
	(arc
		(start 99.610164 -230.57612)
		(mid 99.422966 -230.525977)
		(end 99.235768 -230.57612)
		(width 0.0889)
		(layer "B.Cu")
		(net "H_CPU1_PREQ_QS_GTL_R_N")
	)
	(arc
		(start 100.549964 -230.57612)
		(mid 100.362766 -230.525977)
		(end 100.175568 -230.57612)
		(width 0.0889)
		(layer "B.Cu")
		(net "H_CPU1_PREQ_QS_GTL_R_N")
	)
	(arc
		(start 92.657168 -230.57612)
		(mid 92.382969 -230.651955)
		(end 92.106496 -230.584756)
		(width 0.0889)
		(layer "B.Cu")
		(net "H_CPU1_PREQ_QS_GTL_R_N")
	)
	(arc
		(start 91.717368 -230.57612)
		(mid 91.440555 -230.65199)
		(end 91.162124 -230.582216)
		(width 0.0889)
		(layer "B.Cu")
		(net "H_CPU1_PREQ_QS_GTL_R_N")
	)
	(segment
		(start 109.760512 -234.156504)
		(end 109.760766 -234.15625)
		(width 0.12954)
		(layer "F.Cu")
		(net "H_CPU1_PRDY_QS_GTL_R_N")
	)
	(segment
		(start 109.760512 -234.69219)
		(end 109.760512 -234.156504)
		(width 0.12954)
		(layer "F.Cu")
		(net "H_CPU1_PRDY_QS_GTL_R_N")
	)
	(via
		(at 82.828638 -202.35291)
		(size 0.6604)
		(drill 0.3302)
		(layers "F.Cu" "B.Cu")
		(net "H_CPU1_PRDY_QS_GTL_R_N")
	)
	(via
		(at 109.760766 -234.15625)
		(size 0.4572)
		(drill 0.2032)
		(layers "F.Cu" "B.Cu")
		(net "H_CPU1_PRDY_QS_GTL_R_N")
	)
	(segment
		(start 102.438454 -225.69805)
		(end 102.429564 -225.69297)
		(width 0.0889)
		(layer "B.Cu")
		(net "H_CPU1_PRDY_QS_GTL_R_N")
	)
	(segment
		(start 107.039918 -231.967786)
		(end 106.934508 -231.862376)
		(width 0.0889)
		(layer "B.Cu")
		(net "H_CPU1_PRDY_QS_GTL_R_N")
	)
	(segment
		(start 94.925896 -225.701606)
		(end 94.911164 -225.69297)
		(width 0.0889)
		(layer "B.Cu")
		(net "H_CPU1_PRDY_QS_GTL_R_N")
	)
	(segment
		(start 104.309164 -228.948488)
		(end 104.303068 -228.944932)
		(width 0.0889)
		(layer "B.Cu")
		(net "H_CPU1_PRDY_QS_GTL_R_N")
	)
	(segment
		(start 91.162124 -225.699066)
		(end 91.15171 -225.69297)
		(width 0.0889)
		(layer "B.Cu")
		(net "H_CPU1_PRDY_QS_GTL_R_N")
	)
	(segment
		(start 109.389418 -234.055412)
		(end 109.008164 -233.831892)
		(width 0.0889)
		(layer "B.Cu")
		(net "H_CPU1_PRDY_QS_GTL_R_N")
	)
	(segment
		(start 102.9081 -226.511866)
		(end 102.89921 -226.506786)
		(width 0.0889)
		(layer "B.Cu")
		(net "H_CPU1_PRDY_QS_GTL_R_N")
	)
	(segment
		(start 108.068364 -232.204006)
		(end 108.062268 -232.20045)
		(width 0.0889)
		(layer "B.Cu")
		(net "H_CPU1_PRDY_QS_GTL_R_N")
	)
	(segment
		(start 101.504496 -225.701606)
		(end 101.489764 -225.69297)
		(width 0.0889)
		(layer "B.Cu")
		(net "H_CPU1_PRDY_QS_GTL_R_N")
	)
	(segment
		(start 98.685096 -225.701606)
		(end 98.678238 -225.697542)
		(width 0.0889)
		(layer "B.Cu")
		(net "H_CPU1_PRDY_QS_GTL_R_N")
	)
	(segment
		(start 82.828638 -202.35291)
		(end 82.828638 -200.97369)
		(width 0.12954)
		(layer "B.Cu")
		(net "H_CPU1_PRDY_QS_GTL_R_N")
	)
	(segment
		(start 95.865696 -225.701606)
		(end 95.850964 -225.69297)
		(width 0.0889)
		(layer "B.Cu")
		(net "H_CPU1_PRDY_QS_GTL_R_N")
	)
	(segment
		(start 83.478624 -184.948576)
		(end 83.478624 -184.496202)
		(width 0.12954)
		(layer "B.Cu")
		(net "H_CPU1_PRDY_QS_GTL_R_N")
	)
	(segment
		(start 102.617016 -226.032822)
		(end 102.617016 -226.017328)
		(width 0.0889)
		(layer "B.Cu")
		(net "H_CPU1_PRDY_QS_GTL_R_N")
	)
	(segment
		(start 107.739942 -232.113328)
		(end 107.3912 -232.113328)
		(width 0.0889)
		(layer "B.Cu")
		(net "H_CPU1_PRDY_QS_GTL_R_N")
	)
	(segment
		(start 84.383118 -188.83249)
		(end 84.383118 -185.85307)
		(width 0.12954)
		(layer "B.Cu")
		(net "H_CPU1_PRDY_QS_GTL_R_N")
	)
	(segment
		(start 103.556816 -227.667058)
		(end 103.556816 -227.64496)
		(width 0.0889)
		(layer "B.Cu")
		(net "H_CPU1_PRDY_QS_GTL_R_N")
	)
	(segment
		(start 79.985108 -208.94294)
		(end 82.828638 -206.09941)
		(width 0.12954)
		(layer "B.Cu")
		(net "H_CPU1_PRDY_QS_GTL_R_N")
	)
	(segment
		(start 93.046296 -225.701606)
		(end 93.031564 -225.69297)
		(width 0.0889)
		(layer "B.Cu")
		(net "H_CPU1_PRDY_QS_GTL_R_N")
	)
	(segment
		(start 105.7275 -229.767384)
		(end 105.71861 -229.762304)
		(width 0.0889)
		(layer "B.Cu")
		(net "H_CPU1_PRDY_QS_GTL_R_N")
	)
	(segment
		(start 82.828638 -200.97369)
		(end 83.656678 -200.14565)
		(width 0.12954)
		(layer "B.Cu")
		(net "H_CPU1_PRDY_QS_GTL_R_N")
	)
	(segment
		(start 108.077254 -232.209086)
		(end 108.068364 -232.204006)
		(width 0.0889)
		(layer "B.Cu")
		(net "H_CPU1_PRDY_QS_GTL_R_N")
	)
	(segment
		(start 79.985108 -221.31528)
		(end 79.985108 -208.94294)
		(width 0.12954)
		(layer "B.Cu")
		(net "H_CPU1_PRDY_QS_GTL_R_N")
	)
	(segment
		(start 99.624896 -225.701606)
		(end 99.610164 -225.69297)
		(width 0.0889)
		(layer "B.Cu")
		(net "H_CPU1_PRDY_QS_GTL_R_N")
	)
	(segment
		(start 106.188764 -230.57612)
		(end 106.176572 -230.569008)
		(width 0.0889)
		(layer "B.Cu")
		(net "H_CPU1_PRDY_QS_GTL_R_N")
	)
	(segment
		(start 108.5469 -233.022902)
		(end 108.53801 -233.017822)
		(width 0.0889)
		(layer "B.Cu")
		(net "H_CPU1_PRDY_QS_GTL_R_N")
	)
	(segment
		(start 103.378254 -227.325682)
		(end 103.369364 -227.320602)
		(width 0.0889)
		(layer "B.Cu")
		(net "H_CPU1_PRDY_QS_GTL_R_N")
	)
	(segment
		(start 88.989662 -225.217482)
		(end 88.989662 -225.194622)
		(width 0.0889)
		(layer "B.Cu")
		(net "H_CPU1_PRDY_QS_GTL_R_N")
	)
	(segment
		(start 83.498182 -224.828354)
		(end 79.985108 -221.31528)
		(width 0.12954)
		(layer "B.Cu")
		(net "H_CPU1_PRDY_QS_GTL_R_N")
	)
	(segment
		(start 84.856066 -224.828354)
		(end 83.498182 -224.828354)
		(width 0.0889)
		(layer "B.Cu")
		(net "H_CPU1_PRDY_QS_GTL_R_N")
	)
	(segment
		(start 100.564696 -225.701606)
		(end 100.549964 -225.69297)
		(width 0.0889)
		(layer "B.Cu")
		(net "H_CPU1_PRDY_QS_GTL_R_N")
	)
	(segment
		(start 83.656678 -200.14565)
		(end 83.656678 -189.55893)
		(width 0.12954)
		(layer "B.Cu")
		(net "H_CPU1_PRDY_QS_GTL_R_N")
	)
	(segment
		(start 103.369364 -227.320602)
		(end 103.357172 -227.31349)
		(width 0.0889)
		(layer "B.Cu")
		(net "H_CPU1_PRDY_QS_GTL_R_N")
	)
	(segment
		(start 83.656678 -189.55893)
		(end 84.383118 -188.83249)
		(width 0.12954)
		(layer "B.Cu")
		(net "H_CPU1_PRDY_QS_GTL_R_N")
	)
	(segment
		(start 93.986096 -225.701606)
		(end 93.971364 -225.69297)
		(width 0.0889)
		(layer "B.Cu")
		(net "H_CPU1_PRDY_QS_GTL_R_N")
	)
	(segment
		(start 82.828638 -206.09941)
		(end 82.828638 -202.35291)
		(width 0.12954)
		(layer "B.Cu")
		(net "H_CPU1_PRDY_QS_GTL_R_N")
	)
	(segment
		(start 108.725462 -233.356404)
		(end 108.725462 -233.34218)
		(width 0.0889)
		(layer "B.Cu")
		(net "H_CPU1_PRDY_QS_GTL_R_N")
	)
	(segment
		(start 103.8479 -228.139752)
		(end 103.83901 -228.134672)
		(width 0.0889)
		(layer "B.Cu")
		(net "H_CPU1_PRDY_QS_GTL_R_N")
	)
	(segment
		(start 84.383118 -185.85307)
		(end 83.478624 -184.948576)
		(width 0.12954)
		(layer "B.Cu")
		(net "H_CPU1_PRDY_QS_GTL_R_N")
	)
	(segment
		(start 106.197654 -230.5812)
		(end 106.188764 -230.57612)
		(width 0.0889)
		(layer "B.Cu")
		(net "H_CPU1_PRDY_QS_GTL_R_N")
	)
	(segment
		(start 92.106496 -225.701606)
		(end 92.091764 -225.69297)
		(width 0.0889)
		(layer "B.Cu")
		(net "H_CPU1_PRDY_QS_GTL_R_N")
	)
	(segment
		(start 90.222578 -225.699066)
		(end 90.212164 -225.69297)
		(width 0.0889)
		(layer "B.Cu")
		(net "H_CPU1_PRDY_QS_GTL_R_N")
	)
	(segment
		(start 97.745296 -225.701606)
		(end 97.730564 -225.69297)
		(width 0.0889)
		(layer "B.Cu")
		(net "H_CPU1_PRDY_QS_GTL_R_N")
	)
	(segment
		(start 96.805496 -225.701606)
		(end 96.790764 -225.69297)
		(width 0.0889)
		(layer "B.Cu")
		(net "H_CPU1_PRDY_QS_GTL_R_N")
	)
	(segment
		(start 98.678238 -225.697542)
		(end 98.670364 -225.69297)
		(width 0.0889)
		(layer "B.Cu")
		(net "H_CPU1_PRDY_QS_GTL_R_N")
	)
	(segment
		(start 105.344214 -229.762304)
		(end 105.329482 -229.77094)
		(width 0.0889)
		(layer "B.Cu")
		(net "H_CPU1_PRDY_QS_GTL_R_N")
	)
	(segment
		(start 85.057996 -224.887536)
		(end 85.043264 -224.8789)
		(width 0.0889)
		(layer "B.Cu")
		(net "H_CPU1_PRDY_QS_GTL_R_N")
	)
	(segment
		(start 104.496616 -229.28834)
		(end 104.496616 -229.272846)
		(width 0.0889)
		(layer "B.Cu")
		(net "H_CPU1_PRDY_QS_GTL_R_N")
	)
	(segment
		(start 89.287096 -225.701606)
		(end 89.272364 -225.69297)
		(width 0.0889)
		(layer "B.Cu")
		(net "H_CPU1_PRDY_QS_GTL_R_N")
	)
	(segment
		(start 104.318054 -228.953568)
		(end 104.309164 -228.948488)
		(width 0.0889)
		(layer "B.Cu")
		(net "H_CPU1_PRDY_QS_GTL_R_N")
	)
	(segment
		(start 108.255816 -232.543858)
		(end 108.255816 -232.528364)
		(width 0.0889)
		(layer "B.Cu")
		(net "H_CPU1_PRDY_QS_GTL_R_N")
	)
	(arc
		(start 105.329482 -229.77094)
		(mid 105.053007 -229.83826)
		(end 104.77881 -229.762304)
		(width 0.0889)
		(layer "B.Cu")
		(net "H_CPU1_PRDY_QS_GTL_R_N")
	)
	(arc
		(start 104.496616 -229.272846)
		(mid 104.448937 -229.089946)
		(end 104.318054 -228.953568)
		(width 0.0889)
		(layer "B.Cu")
		(net "H_CPU1_PRDY_QS_GTL_R_N")
	)
	(arc
		(start 109.008164 -233.831892)
		(mid 108.804683 -233.631088)
		(end 108.725462 -233.356404)
		(width 0.0889)
		(layer "B.Cu")
		(net "H_CPU1_PRDY_QS_GTL_R_N")
	)
	(arc
		(start 95.850964 -225.69297)
		(mid 95.663766 -225.642827)
		(end 95.476568 -225.69297)
		(width 0.0889)
		(layer "B.Cu")
		(net "H_CPU1_PRDY_QS_GTL_R_N")
	)
	(arc
		(start 95.476568 -225.69297)
		(mid 95.202339 -225.768895)
		(end 94.925896 -225.701606)
		(width 0.0889)
		(layer "B.Cu")
		(net "H_CPU1_PRDY_QS_GTL_R_N")
	)
	(arc
		(start 92.091764 -225.69297)
		(mid 91.904566 -225.642827)
		(end 91.717368 -225.69297)
		(width 0.0889)
		(layer "B.Cu")
		(net "H_CPU1_PRDY_QS_GTL_R_N")
	)
	(arc
		(start 96.416368 -225.69297)
		(mid 96.142139 -225.768895)
		(end 95.865696 -225.701606)
		(width 0.0889)
		(layer "B.Cu")
		(net "H_CPU1_PRDY_QS_GTL_R_N")
	)
	(arc
		(start 108.53801 -233.017822)
		(mid 108.335187 -232.817591)
		(end 108.255816 -232.543858)
		(width 0.0889)
		(layer "B.Cu")
		(net "H_CPU1_PRDY_QS_GTL_R_N")
	)
	(arc
		(start 106.376216 -230.900478)
		(mid 106.328537 -230.717578)
		(end 106.197654 -230.5812)
		(width 0.0889)
		(layer "B.Cu")
		(net "H_CPU1_PRDY_QS_GTL_R_N")
	)
	(arc
		(start 85.608668 -224.8789)
		(mid 85.334469 -224.954735)
		(end 85.057996 -224.887536)
		(width 0.0889)
		(layer "B.Cu")
		(net "H_CPU1_PRDY_QS_GTL_R_N")
	)
	(arc
		(start 87.488268 -224.8789)
		(mid 87.205566 -224.954676)
		(end 86.922864 -224.8789)
		(width 0.0889)
		(layer "B.Cu")
		(net "H_CPU1_PRDY_QS_GTL_R_N")
	)
	(arc
		(start 93.031564 -225.69297)
		(mid 92.844366 -225.642827)
		(end 92.657168 -225.69297)
		(width 0.0889)
		(layer "B.Cu")
		(net "H_CPU1_PRDY_QS_GTL_R_N")
	)
	(arc
		(start 108.725462 -233.34218)
		(mid 108.677783 -233.15928)
		(end 108.5469 -233.022902)
		(width 0.0889)
		(layer "B.Cu")
		(net "H_CPU1_PRDY_QS_GTL_R_N")
	)
	(arc
		(start 86.922864 -224.8789)
		(mid 86.735666 -224.828757)
		(end 86.548468 -224.8789)
		(width 0.0889)
		(layer "B.Cu")
		(net "H_CPU1_PRDY_QS_GTL_R_N")
	)
	(arc
		(start 91.717368 -225.69297)
		(mid 91.440555 -225.768806)
		(end 91.162124 -225.699066)
		(width 0.0889)
		(layer "B.Cu")
		(net "H_CPU1_PRDY_QS_GTL_R_N")
	)
	(arc
		(start 85.983064 -224.8789)
		(mid 85.795866 -224.828757)
		(end 85.608668 -224.8789)
		(width 0.0889)
		(layer "B.Cu")
		(net "H_CPU1_PRDY_QS_GTL_R_N")
	)
	(arc
		(start 99.235768 -225.69297)
		(mid 98.961539 -225.768895)
		(end 98.685096 -225.701606)
		(width 0.0889)
		(layer "B.Cu")
		(net "H_CPU1_PRDY_QS_GTL_R_N")
	)
	(arc
		(start 90.777314 -225.69297)
		(mid 90.500755 -225.768679)
		(end 90.222578 -225.699066)
		(width 0.0889)
		(layer "B.Cu")
		(net "H_CPU1_PRDY_QS_GTL_R_N")
	)
	(arc
		(start 103.357172 -227.31349)
		(mid 103.158944 -227.107642)
		(end 103.086662 -226.831144)
		(width 0.0889)
		(layer "B.Cu")
		(net "H_CPU1_PRDY_QS_GTL_R_N")
	)
	(arc
		(start 101.489764 -225.69297)
		(mid 101.302566 -225.642827)
		(end 101.115368 -225.69297)
		(width 0.0889)
		(layer "B.Cu")
		(net "H_CPU1_PRDY_QS_GTL_R_N")
	)
	(arc
		(start 102.89921 -226.506786)
		(mid 102.696387 -226.306555)
		(end 102.617016 -226.032822)
		(width 0.0889)
		(layer "B.Cu")
		(net "H_CPU1_PRDY_QS_GTL_R_N")
	)
	(arc
		(start 104.77881 -229.762304)
		(mid 104.575987 -229.562073)
		(end 104.496616 -229.28834)
		(width 0.0889)
		(layer "B.Cu")
		(net "H_CPU1_PRDY_QS_GTL_R_N")
	)
	(arc
		(start 100.175568 -225.69297)
		(mid 99.901339 -225.768895)
		(end 99.624896 -225.701606)
		(width 0.0889)
		(layer "B.Cu")
		(net "H_CPU1_PRDY_QS_GTL_R_N")
	)
	(arc
		(start 99.610164 -225.69297)
		(mid 99.422966 -225.642827)
		(end 99.235768 -225.69297)
		(width 0.0889)
		(layer "B.Cu")
		(net "H_CPU1_PRDY_QS_GTL_R_N")
	)
	(arc
		(start 100.549964 -225.69297)
		(mid 100.362766 -225.642827)
		(end 100.175568 -225.69297)
		(width 0.0889)
		(layer "B.Cu")
		(net "H_CPU1_PRDY_QS_GTL_R_N")
	)
	(arc
		(start 93.596968 -225.69297)
		(mid 93.322739 -225.768895)
		(end 93.046296 -225.701606)
		(width 0.0889)
		(layer "B.Cu")
		(net "H_CPU1_PRDY_QS_GTL_R_N")
	)
	(arc
		(start 98.670364 -225.69297)
		(mid 98.483166 -225.642827)
		(end 98.295968 -225.69297)
		(width 0.0889)
		(layer "B.Cu")
		(net "H_CPU1_PRDY_QS_GTL_R_N")
	)
	(arc
		(start 108.062268 -232.20045)
		(mid 107.906893 -232.135468)
		(end 107.739942 -232.113328)
		(width 0.0889)
		(layer "B.Cu")
		(net "H_CPU1_PRDY_QS_GTL_R_N")
	)
	(arc
		(start 94.911164 -225.69297)
		(mid 94.723966 -225.642827)
		(end 94.536768 -225.69297)
		(width 0.0889)
		(layer "B.Cu")
		(net "H_CPU1_PRDY_QS_GTL_R_N")
	)
	(arc
		(start 89.837768 -225.69297)
		(mid 89.563539 -225.768895)
		(end 89.287096 -225.701606)
		(width 0.0889)
		(layer "B.Cu")
		(net "H_CPU1_PRDY_QS_GTL_R_N")
	)
	(arc
		(start 90.212164 -225.69297)
		(mid 90.024966 -225.642827)
		(end 89.837768 -225.69297)
		(width 0.0889)
		(layer "B.Cu")
		(net "H_CPU1_PRDY_QS_GTL_R_N")
	)
	(arc
		(start 106.611166 -231.273096)
		(mid 106.439878 -231.120723)
		(end 106.376216 -230.900478)
		(width 0.0889)
		(layer "B.Cu")
		(net "H_CPU1_PRDY_QS_GTL_R_N")
	)
	(arc
		(start 88.989662 -225.194622)
		(mid 88.937392 -225.012257)
		(end 88.802464 -224.8789)
		(width 0.0889)
		(layer "B.Cu")
		(net "H_CPU1_PRDY_QS_GTL_R_N")
	)
	(arc
		(start 91.15171 -225.69297)
		(mid 90.964512 -225.642827)
		(end 90.777314 -225.69297)
		(width 0.0889)
		(layer "B.Cu")
		(net "H_CPU1_PRDY_QS_GTL_R_N")
	)
	(arc
		(start 88.428068 -224.8789)
		(mid 88.145366 -224.954676)
		(end 87.862664 -224.8789)
		(width 0.0889)
		(layer "B.Cu")
		(net "H_CPU1_PRDY_QS_GTL_R_N")
	)
	(arc
		(start 103.556816 -227.64496)
		(mid 103.509137 -227.46206)
		(end 103.378254 -227.325682)
		(width 0.0889)
		(layer "B.Cu")
		(net "H_CPU1_PRDY_QS_GTL_R_N")
	)
	(arc
		(start 109.760766 -234.15625)
		(mid 109.56837 -234.130588)
		(end 109.389418 -234.055412)
		(width 0.0889)
		(layer "B.Cu")
		(net "H_CPU1_PRDY_QS_GTL_R_N")
	)
	(arc
		(start 94.536768 -225.69297)
		(mid 94.262539 -225.768895)
		(end 93.986096 -225.701606)
		(width 0.0889)
		(layer "B.Cu")
		(net "H_CPU1_PRDY_QS_GTL_R_N")
	)
	(arc
		(start 103.086662 -226.831144)
		(mid 103.038983 -226.648244)
		(end 102.9081 -226.511866)
		(width 0.0889)
		(layer "B.Cu")
		(net "H_CPU1_PRDY_QS_GTL_R_N")
	)
	(arc
		(start 106.934508 -231.862376)
		(mid 106.88039 -231.781383)
		(end 106.861356 -231.685846)
		(width 0.0889)
		(layer "B.Cu")
		(net "H_CPU1_PRDY_QS_GTL_R_N")
	)
	(arc
		(start 93.971364 -225.69297)
		(mid 93.784166 -225.642827)
		(end 93.596968 -225.69297)
		(width 0.0889)
		(layer "B.Cu")
		(net "H_CPU1_PRDY_QS_GTL_R_N")
	)
	(arc
		(start 102.617016 -226.017328)
		(mid 102.569337 -225.834428)
		(end 102.438454 -225.69805)
		(width 0.0889)
		(layer "B.Cu")
		(net "H_CPU1_PRDY_QS_GTL_R_N")
	)
	(arc
		(start 85.043264 -224.8789)
		(mid 84.952992 -224.841301)
		(end 84.856066 -224.828354)
		(width 0.0889)
		(layer "B.Cu")
		(net "H_CPU1_PRDY_QS_GTL_R_N")
	)
	(arc
		(start 106.861356 -231.685846)
		(mid 106.793927 -231.444515)
		(end 106.611166 -231.273096)
		(width 0.0889)
		(layer "B.Cu")
		(net "H_CPU1_PRDY_QS_GTL_R_N")
	)
	(arc
		(start 98.295968 -225.69297)
		(mid 98.021739 -225.768895)
		(end 97.745296 -225.701606)
		(width 0.0889)
		(layer "B.Cu")
		(net "H_CPU1_PRDY_QS_GTL_R_N")
	)
	(arc
		(start 103.83901 -228.134672)
		(mid 103.637728 -227.937185)
		(end 103.556816 -227.667058)
		(width 0.0889)
		(layer "B.Cu")
		(net "H_CPU1_PRDY_QS_GTL_R_N")
	)
	(arc
		(start 96.790764 -225.69297)
		(mid 96.603566 -225.642827)
		(end 96.416368 -225.69297)
		(width 0.0889)
		(layer "B.Cu")
		(net "H_CPU1_PRDY_QS_GTL_R_N")
	)
	(arc
		(start 106.176572 -230.569008)
		(mid 105.978344 -230.36316)
		(end 105.906062 -230.086662)
		(width 0.0889)
		(layer "B.Cu")
		(net "H_CPU1_PRDY_QS_GTL_R_N")
	)
	(arc
		(start 88.802464 -224.8789)
		(mid 88.615266 -224.828757)
		(end 88.428068 -224.8789)
		(width 0.0889)
		(layer "B.Cu")
		(net "H_CPU1_PRDY_QS_GTL_R_N")
	)
	(arc
		(start 107.3912 -232.113328)
		(mid 107.201074 -232.07551)
		(end 107.039918 -231.967786)
		(width 0.0889)
		(layer "B.Cu")
		(net "H_CPU1_PRDY_QS_GTL_R_N")
	)
	(arc
		(start 97.730564 -225.69297)
		(mid 97.543366 -225.642827)
		(end 97.356168 -225.69297)
		(width 0.0889)
		(layer "B.Cu")
		(net "H_CPU1_PRDY_QS_GTL_R_N")
	)
	(arc
		(start 105.71861 -229.762304)
		(mid 105.531412 -229.712161)
		(end 105.344214 -229.762304)
		(width 0.0889)
		(layer "B.Cu")
		(net "H_CPU1_PRDY_QS_GTL_R_N")
	)
	(arc
		(start 102.055168 -225.69297)
		(mid 101.780939 -225.768895)
		(end 101.504496 -225.701606)
		(width 0.0889)
		(layer "B.Cu")
		(net "H_CPU1_PRDY_QS_GTL_R_N")
	)
	(arc
		(start 104.303068 -228.944932)
		(mid 104.100481 -228.738581)
		(end 104.026462 -228.45903)
		(width 0.0889)
		(layer "B.Cu")
		(net "H_CPU1_PRDY_QS_GTL_R_N")
	)
	(arc
		(start 104.026462 -228.45903)
		(mid 103.978783 -228.27613)
		(end 103.8479 -228.139752)
		(width 0.0889)
		(layer "B.Cu")
		(net "H_CPU1_PRDY_QS_GTL_R_N")
	)
	(arc
		(start 97.356168 -225.69297)
		(mid 97.081939 -225.768895)
		(end 96.805496 -225.701606)
		(width 0.0889)
		(layer "B.Cu")
		(net "H_CPU1_PRDY_QS_GTL_R_N")
	)
	(arc
		(start 102.429564 -225.69297)
		(mid 102.242366 -225.642827)
		(end 102.055168 -225.69297)
		(width 0.0889)
		(layer "B.Cu")
		(net "H_CPU1_PRDY_QS_GTL_R_N")
	)
	(arc
		(start 87.862664 -224.8789)
		(mid 87.675466 -224.828757)
		(end 87.488268 -224.8789)
		(width 0.0889)
		(layer "B.Cu")
		(net "H_CPU1_PRDY_QS_GTL_R_N")
	)
	(arc
		(start 86.548468 -224.8789)
		(mid 86.265766 -224.954676)
		(end 85.983064 -224.8789)
		(width 0.0889)
		(layer "B.Cu")
		(net "H_CPU1_PRDY_QS_GTL_R_N")
	)
	(arc
		(start 108.255816 -232.528364)
		(mid 108.208137 -232.345464)
		(end 108.077254 -232.209086)
		(width 0.0889)
		(layer "B.Cu")
		(net "H_CPU1_PRDY_QS_GTL_R_N")
	)
	(arc
		(start 105.906062 -230.086662)
		(mid 105.858383 -229.903762)
		(end 105.7275 -229.767384)
		(width 0.0889)
		(layer "B.Cu")
		(net "H_CPU1_PRDY_QS_GTL_R_N")
	)
	(arc
		(start 101.115368 -225.69297)
		(mid 100.841139 -225.768895)
		(end 100.564696 -225.701606)
		(width 0.0889)
		(layer "B.Cu")
		(net "H_CPU1_PRDY_QS_GTL_R_N")
	)
	(arc
		(start 89.272364 -225.69297)
		(mid 89.068883 -225.492166)
		(end 88.989662 -225.217482)
		(width 0.0889)
		(layer "B.Cu")
		(net "H_CPU1_PRDY_QS_GTL_R_N")
	)
	(arc
		(start 92.657168 -225.69297)
		(mid 92.382939 -225.768895)
		(end 92.106496 -225.701606)
		(width 0.0889)
		(layer "B.Cu")
		(net "H_CPU1_PRDY_QS_GTL_R_N")
	)
	(segment
		(start 119.158766 -229.808532)
		(end 119.158766 -229.272846)
		(width 0.12954)
		(layer "F.Cu")
		(net "H_CPU1_PM_FAST_WAKE_N")
	)
	(segment
		(start 119.158512 -229.808786)
		(end 119.158766 -229.808532)
		(width 0.12954)
		(layer "F.Cu")
		(net "H_CPU1_PM_FAST_WAKE_N")
	)
	(via
		(at 119.158766 -229.272846)
		(size 0.4572)
		(drill 0.2032)
		(layers "F.Cu" "B.Cu")
		(net "H_CPU1_PM_FAST_WAKE_N")
	)
	(via
		(at 152.019762 -195.308474)
		(size 0.6604)
		(drill 0.3302)
		(layers "F.Cu" "B.Cu")
		(net "H_CPU1_PM_FAST_WAKE_N")
	)
	(segment
		(start 150.679658 -219.499688)
		(end 150.679658 -196.648578)
		(width 0.12954)
		(layer "B.Cu")
		(net "H_CPU1_PM_FAST_WAKE_N")
	)
	(segment
		(start 152.019762 -195.308474)
		(end 154.134566 -193.19367)
		(width 0.12954)
		(layer "B.Cu")
		(net "H_CPU1_PM_FAST_WAKE_N")
	)
	(segment
		(start 120.366282 -228.143308)
		(end 120.381014 -228.134672)
		(width 0.0889)
		(layer "B.Cu")
		(net "H_CPU1_PM_FAST_WAKE_N")
	)
	(segment
		(start 123.185682 -228.143308)
		(end 123.200414 -228.134672)
		(width 0.0889)
		(layer "B.Cu")
		(net "H_CPU1_PM_FAST_WAKE_N")
	)
	(segment
		(start 119.432324 -228.139752)
		(end 119.441214 -228.134672)
		(width 0.0889)
		(layer "B.Cu")
		(net "H_CPU1_PM_FAST_WAKE_N")
	)
	(segment
		(start 150.679658 -196.648578)
		(end 152.019762 -195.308474)
		(width 0.12954)
		(layer "B.Cu")
		(net "H_CPU1_PM_FAST_WAKE_N")
	)
	(segment
		(start 129.764282 -228.143308)
		(end 129.779014 -228.134672)
		(width 0.0889)
		(layer "B.Cu")
		(net "H_CPU1_PM_FAST_WAKE_N")
	)
	(segment
		(start 130.704082 -228.143308)
		(end 130.718814 -228.134672)
		(width 0.0889)
		(layer "B.Cu")
		(net "H_CPU1_PM_FAST_WAKE_N")
	)
	(segment
		(start 134.4676 -228.140768)
		(end 134.478014 -228.134672)
		(width 0.0889)
		(layer "B.Cu")
		(net "H_CPU1_PM_FAST_WAKE_N")
	)
	(segment
		(start 142.624556 -227.55479)
		(end 150.679658 -219.499688)
		(width 0.12954)
		(layer "B.Cu")
		(net "H_CPU1_PM_FAST_WAKE_N")
	)
	(segment
		(start 126.009654 -228.140768)
		(end 126.020068 -228.134672)
		(width 0.0889)
		(layer "B.Cu")
		(net "H_CPU1_PM_FAST_WAKE_N")
	)
	(segment
		(start 121.306082 -228.143308)
		(end 121.320814 -228.134672)
		(width 0.0889)
		(layer "B.Cu")
		(net "H_CPU1_PM_FAST_WAKE_N")
	)
	(segment
		(start 137.814304 -228.05009)
		(end 138.187684 -227.67671)
		(width 0.12954)
		(layer "B.Cu")
		(net "H_CPU1_PM_FAST_WAKE_N")
	)
	(segment
		(start 124.125482 -228.143308)
		(end 124.140214 -228.134672)
		(width 0.0889)
		(layer "B.Cu")
		(net "H_CPU1_PM_FAST_WAKE_N")
	)
	(segment
		(start 125.065282 -228.143308)
		(end 125.080014 -228.134672)
		(width 0.0889)
		(layer "B.Cu")
		(net "H_CPU1_PM_FAST_WAKE_N")
	)
	(segment
		(start 136.357868 -228.134672)
		(end 136.44245 -228.05009)
		(width 0.0889)
		(layer "B.Cu")
		(net "H_CPU1_PM_FAST_WAKE_N")
	)
	(segment
		(start 136.950958 -228.05009)
		(end 137.814304 -228.05009)
		(width 0.12954)
		(layer "B.Cu")
		(net "H_CPU1_PM_FAST_WAKE_N")
	)
	(segment
		(start 119.253762 -228.474524)
		(end 119.253762 -228.45903)
		(width 0.0889)
		(layer "B.Cu")
		(net "H_CPU1_PM_FAST_WAKE_N")
	)
	(segment
		(start 140.334238 -227.55479)
		(end 142.624556 -227.55479)
		(width 0.12954)
		(layer "B.Cu")
		(net "H_CPU1_PM_FAST_WAKE_N")
	)
	(segment
		(start 132.588254 -228.140768)
		(end 132.598668 -228.134672)
		(width 0.0889)
		(layer "B.Cu")
		(net "H_CPU1_PM_FAST_WAKE_N")
	)
	(segment
		(start 131.643882 -228.143308)
		(end 131.658614 -228.134672)
		(width 0.0889)
		(layer "B.Cu")
		(net "H_CPU1_PM_FAST_WAKE_N")
	)
	(segment
		(start 138.187684 -227.67671)
		(end 140.212318 -227.67671)
		(width 0.12954)
		(layer "B.Cu")
		(net "H_CPU1_PM_FAST_WAKE_N")
	)
	(segment
		(start 126.9492 -228.140768)
		(end 126.959614 -228.134672)
		(width 0.0889)
		(layer "B.Cu")
		(net "H_CPU1_PM_FAST_WAKE_N")
	)
	(segment
		(start 135.407654 -228.140768)
		(end 135.418068 -228.134672)
		(width 0.0889)
		(layer "B.Cu")
		(net "H_CPU1_PM_FAST_WAKE_N")
	)
	(segment
		(start 154.134566 -193.19367)
		(end 154.48915 -193.19367)
		(width 0.12954)
		(layer "B.Cu")
		(net "H_CPU1_PM_FAST_WAKE_N")
	)
	(segment
		(start 140.212318 -227.67671)
		(end 140.334238 -227.55479)
		(width 0.12954)
		(layer "B.Cu")
		(net "H_CPU1_PM_FAST_WAKE_N")
	)
	(segment
		(start 136.44245 -228.05009)
		(end 136.950958 -228.05009)
		(width 0.0889)
		(layer "B.Cu")
		(net "H_CPU1_PM_FAST_WAKE_N")
	)
	(arc
		(start 125.080014 -228.134672)
		(mid 125.267212 -228.084529)
		(end 125.45441 -228.134672)
		(width 0.0889)
		(layer "B.Cu")
		(net "H_CPU1_PM_FAST_WAKE_N")
	)
	(arc
		(start 119.441214 -228.134672)
		(mid 119.628412 -228.084529)
		(end 119.81561 -228.134672)
		(width 0.0889)
		(layer "B.Cu")
		(net "H_CPU1_PM_FAST_WAKE_N")
	)
	(arc
		(start 129.779014 -228.134672)
		(mid 129.966212 -228.084529)
		(end 130.15341 -228.134672)
		(width 0.0889)
		(layer "B.Cu")
		(net "H_CPU1_PM_FAST_WAKE_N")
	)
	(arc
		(start 120.75541 -228.134672)
		(mid 121.029639 -228.210597)
		(end 121.306082 -228.143308)
		(width 0.0889)
		(layer "B.Cu")
		(net "H_CPU1_PM_FAST_WAKE_N")
	)
	(arc
		(start 126.959614 -228.134672)
		(mid 127.146812 -228.084529)
		(end 127.33401 -228.134672)
		(width 0.0889)
		(layer "B.Cu")
		(net "H_CPU1_PM_FAST_WAKE_N")
	)
	(arc
		(start 119.253762 -228.45903)
		(mid 119.301441 -228.27613)
		(end 119.432324 -228.139752)
		(width 0.0889)
		(layer "B.Cu")
		(net "H_CPU1_PM_FAST_WAKE_N")
	)
	(arc
		(start 125.45441 -228.134672)
		(mid 125.731223 -228.210508)
		(end 126.009654 -228.140768)
		(width 0.0889)
		(layer "B.Cu")
		(net "H_CPU1_PM_FAST_WAKE_N")
	)
	(arc
		(start 132.598668 -228.134672)
		(mid 132.785866 -228.084529)
		(end 132.973064 -228.134672)
		(width 0.0889)
		(layer "B.Cu")
		(net "H_CPU1_PM_FAST_WAKE_N")
	)
	(arc
		(start 131.09321 -228.134672)
		(mid 131.367439 -228.210597)
		(end 131.643882 -228.143308)
		(width 0.0889)
		(layer "B.Cu")
		(net "H_CPU1_PM_FAST_WAKE_N")
	)
	(arc
		(start 130.15341 -228.134672)
		(mid 130.427639 -228.210597)
		(end 130.704082 -228.143308)
		(width 0.0889)
		(layer "B.Cu")
		(net "H_CPU1_PM_FAST_WAKE_N")
	)
	(arc
		(start 134.478014 -228.134672)
		(mid 134.665212 -228.084529)
		(end 134.85241 -228.134672)
		(width 0.0889)
		(layer "B.Cu")
		(net "H_CPU1_PM_FAST_WAKE_N")
	)
	(arc
		(start 127.899414 -228.134672)
		(mid 128.086612 -228.084529)
		(end 128.27381 -228.134672)
		(width 0.0889)
		(layer "B.Cu")
		(net "H_CPU1_PM_FAST_WAKE_N")
	)
	(arc
		(start 128.27381 -228.134672)
		(mid 128.556512 -228.210414)
		(end 128.839214 -228.134672)
		(width 0.0889)
		(layer "B.Cu")
		(net "H_CPU1_PM_FAST_WAKE_N")
	)
	(arc
		(start 121.320814 -228.134672)
		(mid 121.508012 -228.084529)
		(end 121.69521 -228.134672)
		(width 0.0889)
		(layer "B.Cu")
		(net "H_CPU1_PM_FAST_WAKE_N")
	)
	(arc
		(start 134.85241 -228.134672)
		(mid 135.129223 -228.210508)
		(end 135.407654 -228.140768)
		(width 0.0889)
		(layer "B.Cu")
		(net "H_CPU1_PM_FAST_WAKE_N")
	)
	(arc
		(start 121.69521 -228.134672)
		(mid 121.977912 -228.210414)
		(end 122.260614 -228.134672)
		(width 0.0889)
		(layer "B.Cu")
		(net "H_CPU1_PM_FAST_WAKE_N")
	)
	(arc
		(start 135.792464 -228.134672)
		(mid 136.075166 -228.210414)
		(end 136.357868 -228.134672)
		(width 0.0889)
		(layer "B.Cu")
		(net "H_CPU1_PM_FAST_WAKE_N")
	)
	(arc
		(start 131.658614 -228.134672)
		(mid 131.845812 -228.084529)
		(end 132.03301 -228.134672)
		(width 0.0889)
		(layer "B.Cu")
		(net "H_CPU1_PM_FAST_WAKE_N")
	)
	(arc
		(start 123.200414 -228.134672)
		(mid 123.387612 -228.084529)
		(end 123.57481 -228.134672)
		(width 0.0889)
		(layer "B.Cu")
		(net "H_CPU1_PM_FAST_WAKE_N")
	)
	(arc
		(start 128.839214 -228.134672)
		(mid 129.026412 -228.084529)
		(end 129.21361 -228.134672)
		(width 0.0889)
		(layer "B.Cu")
		(net "H_CPU1_PM_FAST_WAKE_N")
	)
	(arc
		(start 133.912864 -228.134672)
		(mid 134.189423 -228.210381)
		(end 134.4676 -228.140768)
		(width 0.0889)
		(layer "B.Cu")
		(net "H_CPU1_PM_FAST_WAKE_N")
	)
	(arc
		(start 129.21361 -228.134672)
		(mid 129.487839 -228.210597)
		(end 129.764282 -228.143308)
		(width 0.0889)
		(layer "B.Cu")
		(net "H_CPU1_PM_FAST_WAKE_N")
	)
	(arc
		(start 126.020068 -228.134672)
		(mid 126.207266 -228.084529)
		(end 126.394464 -228.134672)
		(width 0.0889)
		(layer "B.Cu")
		(net "H_CPU1_PM_FAST_WAKE_N")
	)
	(arc
		(start 123.57481 -228.134672)
		(mid 123.849039 -228.210597)
		(end 124.125482 -228.143308)
		(width 0.0889)
		(layer "B.Cu")
		(net "H_CPU1_PM_FAST_WAKE_N")
	)
	(arc
		(start 120.381014 -228.134672)
		(mid 120.568212 -228.084529)
		(end 120.75541 -228.134672)
		(width 0.0889)
		(layer "B.Cu")
		(net "H_CPU1_PM_FAST_WAKE_N")
	)
	(arc
		(start 132.03301 -228.134672)
		(mid 132.309823 -228.210508)
		(end 132.588254 -228.140768)
		(width 0.0889)
		(layer "B.Cu")
		(net "H_CPU1_PM_FAST_WAKE_N")
	)
	(arc
		(start 119.81561 -228.134672)
		(mid 120.089839 -228.210597)
		(end 120.366282 -228.143308)
		(width 0.0889)
		(layer "B.Cu")
		(net "H_CPU1_PM_FAST_WAKE_N")
	)
	(arc
		(start 122.63501 -228.134672)
		(mid 122.909239 -228.210597)
		(end 123.185682 -228.143308)
		(width 0.0889)
		(layer "B.Cu")
		(net "H_CPU1_PM_FAST_WAKE_N")
	)
	(arc
		(start 126.394464 -228.134672)
		(mid 126.671023 -228.210381)
		(end 126.9492 -228.140768)
		(width 0.0889)
		(layer "B.Cu")
		(net "H_CPU1_PM_FAST_WAKE_N")
	)
	(arc
		(start 127.33401 -228.134672)
		(mid 127.616712 -228.210414)
		(end 127.899414 -228.134672)
		(width 0.0889)
		(layer "B.Cu")
		(net "H_CPU1_PM_FAST_WAKE_N")
	)
	(arc
		(start 135.418068 -228.134672)
		(mid 135.605266 -228.084529)
		(end 135.792464 -228.134672)
		(width 0.0889)
		(layer "B.Cu")
		(net "H_CPU1_PM_FAST_WAKE_N")
	)
	(arc
		(start 124.51461 -228.134672)
		(mid 124.788839 -228.210597)
		(end 125.065282 -228.143308)
		(width 0.0889)
		(layer "B.Cu")
		(net "H_CPU1_PM_FAST_WAKE_N")
	)
	(arc
		(start 133.538468 -228.134672)
		(mid 133.725666 -228.084529)
		(end 133.912864 -228.134672)
		(width 0.0889)
		(layer "B.Cu")
		(net "H_CPU1_PM_FAST_WAKE_N")
	)
	(arc
		(start 132.973064 -228.134672)
		(mid 133.255766 -228.210414)
		(end 133.538468 -228.134672)
		(width 0.0889)
		(layer "B.Cu")
		(net "H_CPU1_PM_FAST_WAKE_N")
	)
	(arc
		(start 119.158766 -229.272846)
		(mid 119.229932 -228.876501)
		(end 119.253762 -228.474524)
		(width 0.0889)
		(layer "B.Cu")
		(net "H_CPU1_PM_FAST_WAKE_N")
	)
	(arc
		(start 122.260614 -228.134672)
		(mid 122.447812 -228.084529)
		(end 122.63501 -228.134672)
		(width 0.0889)
		(layer "B.Cu")
		(net "H_CPU1_PM_FAST_WAKE_N")
	)
	(arc
		(start 130.718814 -228.134672)
		(mid 130.906012 -228.084529)
		(end 131.09321 -228.134672)
		(width 0.0889)
		(layer "B.Cu")
		(net "H_CPU1_PM_FAST_WAKE_N")
	)
	(arc
		(start 124.140214 -228.134672)
		(mid 124.327412 -228.084529)
		(end 124.51461 -228.134672)
		(width 0.0889)
		(layer "B.Cu")
		(net "H_CPU1_PM_FAST_WAKE_N")
	)
	(segment
		(start 102.242366 -228.180646)
		(end 102.242366 -227.64496)
		(width 0.12954)
		(layer "F.Cu")
		(net "H_CPU1_NMI_LVC1_N")
	)
	(segment
		(start 102.242112 -228.1809)
		(end 102.242366 -228.180646)
		(width 0.12954)
		(layer "F.Cu")
		(net "H_CPU1_NMI_LVC1_N")
	)
	(via
		(at 102.242366 -227.64496)
		(size 0.4572)
		(drill 0.2032)
		(layers "F.Cu" "B.Cu")
		(net "H_CPU1_NMI_LVC1_N")
	)
	(via
		(at 80.079596 -204.098398)
		(size 0.6604)
		(drill 0.3302)
		(layers "F.Cu" "B.Cu")
		(net "H_CPU1_NMI_LVC1_N")
	)
	(segment
		(start 102.085902 -227.915978)
		(end 101.996748 -227.939854)
		(width 0.0889)
		(layer "B.Cu")
		(net "H_CPU1_NMI_LVC1_N")
	)
	(segment
		(start 83.8708 -228.020372)
		(end 83.298284 -227.447856)
		(width 0.0889)
		(layer "B.Cu")
		(net "H_CPU1_NMI_LVC1_N")
	)
	(segment
		(start 81.368138 -188.46419)
		(end 81.914238 -187.91809)
		(width 0.12954)
		(layer "B.Cu")
		(net "H_CPU1_NMI_LVC1_N")
	)
	(segment
		(start 77.790548 -222.49384)
		(end 77.790548 -206.387446)
		(width 0.12954)
		(layer "B.Cu")
		(net "H_CPU1_NMI_LVC1_N")
	)
	(segment
		(start 81.914238 -187.91809)
		(end 81.914238 -185.941716)
		(width 0.12954)
		(layer "B.Cu")
		(net "H_CPU1_NMI_LVC1_N")
	)
	(segment
		(start 98.678238 -227.964746)
		(end 98.670364 -227.969318)
		(width 0.0889)
		(layer "B.Cu")
		(net "H_CPU1_NMI_LVC1_N")
	)
	(segment
		(start 80.079596 -204.098398)
		(end 80.421734 -203.75626)
		(width 0.12954)
		(layer "B.Cu")
		(net "H_CPU1_NMI_LVC1_N")
	)
	(segment
		(start 77.790548 -206.387446)
		(end 80.079596 -204.098398)
		(width 0.12954)
		(layer "B.Cu")
		(net "H_CPU1_NMI_LVC1_N")
	)
	(segment
		(start 89.287096 -227.960682)
		(end 89.272364 -227.969318)
		(width 0.0889)
		(layer "B.Cu")
		(net "H_CPU1_NMI_LVC1_N")
	)
	(segment
		(start 80.421734 -198.925688)
		(end 81.368138 -197.979284)
		(width 0.12954)
		(layer "B.Cu")
		(net "H_CPU1_NMI_LVC1_N")
	)
	(segment
		(start 83.298284 -227.447856)
		(end 82.744564 -227.447856)
		(width 0.12954)
		(layer "B.Cu")
		(net "H_CPU1_NMI_LVC1_N")
	)
	(segment
		(start 81.368138 -197.979284)
		(end 81.368138 -188.46419)
		(width 0.12954)
		(layer "B.Cu")
		(net "H_CPU1_NMI_LVC1_N")
	)
	(segment
		(start 100.564696 -227.960682)
		(end 100.549964 -227.969318)
		(width 0.0889)
		(layer "B.Cu")
		(net "H_CPU1_NMI_LVC1_N")
	)
	(segment
		(start 81.446624 -185.474102)
		(end 81.446624 -184.496202)
		(width 0.12954)
		(layer "B.Cu")
		(net "H_CPU1_NMI_LVC1_N")
	)
	(segment
		(start 82.744564 -227.447856)
		(end 77.790548 -222.49384)
		(width 0.12954)
		(layer "B.Cu")
		(net "H_CPU1_NMI_LVC1_N")
	)
	(segment
		(start 95.865696 -227.960682)
		(end 95.850964 -227.969318)
		(width 0.0889)
		(layer "B.Cu")
		(net "H_CPU1_NMI_LVC1_N")
	)
	(segment
		(start 80.421734 -203.75626)
		(end 80.421734 -198.925688)
		(width 0.12954)
		(layer "B.Cu")
		(net "H_CPU1_NMI_LVC1_N")
	)
	(segment
		(start 87.958168 -227.969318)
		(end 87.947754 -227.963222)
		(width 0.0889)
		(layer "B.Cu")
		(net "H_CPU1_NMI_LVC1_N")
	)
	(segment
		(start 101.504496 -227.960682)
		(end 101.489764 -227.969318)
		(width 0.0889)
		(layer "B.Cu")
		(net "H_CPU1_NMI_LVC1_N")
	)
	(segment
		(start 93.046296 -227.960682)
		(end 93.031564 -227.969318)
		(width 0.0889)
		(layer "B.Cu")
		(net "H_CPU1_NMI_LVC1_N")
	)
	(segment
		(start 96.805496 -227.960682)
		(end 96.790764 -227.969318)
		(width 0.0889)
		(layer "B.Cu")
		(net "H_CPU1_NMI_LVC1_N")
	)
	(segment
		(start 87.205058 -228.020372)
		(end 83.8708 -228.020372)
		(width 0.0889)
		(layer "B.Cu")
		(net "H_CPU1_NMI_LVC1_N")
	)
	(segment
		(start 102.242366 -227.64496)
		(end 102.085902 -227.915978)
		(width 0.0889)
		(layer "B.Cu")
		(net "H_CPU1_NMI_LVC1_N")
	)
	(segment
		(start 94.925896 -227.960682)
		(end 94.911164 -227.969318)
		(width 0.0889)
		(layer "B.Cu")
		(net "H_CPU1_NMI_LVC1_N")
	)
	(segment
		(start 99.620324 -227.963222)
		(end 99.60991 -227.969318)
		(width 0.0889)
		(layer "B.Cu")
		(net "H_CPU1_NMI_LVC1_N")
	)
	(segment
		(start 91.717114 -227.969318)
		(end 91.7067 -227.963222)
		(width 0.0889)
		(layer "B.Cu")
		(net "H_CPU1_NMI_LVC1_N")
	)
	(segment
		(start 88.347296 -227.960682)
		(end 88.332564 -227.969318)
		(width 0.0889)
		(layer "B.Cu")
		(net "H_CPU1_NMI_LVC1_N")
	)
	(segment
		(start 90.226896 -227.960682)
		(end 90.212164 -227.969318)
		(width 0.0889)
		(layer "B.Cu")
		(net "H_CPU1_NMI_LVC1_N")
	)
	(segment
		(start 93.986096 -227.960682)
		(end 93.971364 -227.969318)
		(width 0.0889)
		(layer "B.Cu")
		(net "H_CPU1_NMI_LVC1_N")
	)
	(segment
		(start 81.914238 -185.941716)
		(end 81.446624 -185.474102)
		(width 0.12954)
		(layer "B.Cu")
		(net "H_CPU1_NMI_LVC1_N")
	)
	(segment
		(start 92.101924 -227.963222)
		(end 92.09151 -227.969318)
		(width 0.0889)
		(layer "B.Cu")
		(net "H_CPU1_NMI_LVC1_N")
	)
	(segment
		(start 98.680778 -227.963222)
		(end 98.678238 -227.964746)
		(width 0.0889)
		(layer "B.Cu")
		(net "H_CPU1_NMI_LVC1_N")
	)
	(arc
		(start 97.730564 -227.969318)
		(mid 97.543366 -228.019461)
		(end 97.356168 -227.969318)
		(width 0.0889)
		(layer "B.Cu")
		(net "H_CPU1_NMI_LVC1_N")
	)
	(arc
		(start 92.657168 -227.969318)
		(mid 92.380355 -227.893482)
		(end 92.101924 -227.963222)
		(width 0.0889)
		(layer "B.Cu")
		(net "H_CPU1_NMI_LVC1_N")
	)
	(arc
		(start 91.151964 -227.969318)
		(mid 90.964766 -228.019461)
		(end 90.777568 -227.969318)
		(width 0.0889)
		(layer "B.Cu")
		(net "H_CPU1_NMI_LVC1_N")
	)
	(arc
		(start 90.212164 -227.969318)
		(mid 90.024966 -228.019461)
		(end 89.837768 -227.969318)
		(width 0.0889)
		(layer "B.Cu")
		(net "H_CPU1_NMI_LVC1_N")
	)
	(arc
		(start 92.09151 -227.969318)
		(mid 91.904312 -228.019461)
		(end 91.717114 -227.969318)
		(width 0.0889)
		(layer "B.Cu")
		(net "H_CPU1_NMI_LVC1_N")
	)
	(arc
		(start 94.911164 -227.969318)
		(mid 94.723966 -228.019461)
		(end 94.536768 -227.969318)
		(width 0.0889)
		(layer "B.Cu")
		(net "H_CPU1_NMI_LVC1_N")
	)
	(arc
		(start 98.295968 -227.969318)
		(mid 98.013266 -227.893576)
		(end 97.730564 -227.969318)
		(width 0.0889)
		(layer "B.Cu")
		(net "H_CPU1_NMI_LVC1_N")
	)
	(arc
		(start 88.332564 -227.969318)
		(mid 88.145366 -228.019461)
		(end 87.958168 -227.969318)
		(width 0.0889)
		(layer "B.Cu")
		(net "H_CPU1_NMI_LVC1_N")
	)
	(arc
		(start 97.356168 -227.969318)
		(mid 97.081939 -227.893393)
		(end 96.805496 -227.960682)
		(width 0.0889)
		(layer "B.Cu")
		(net "H_CPU1_NMI_LVC1_N")
	)
	(arc
		(start 101.115368 -227.969318)
		(mid 100.841139 -227.893393)
		(end 100.564696 -227.960682)
		(width 0.0889)
		(layer "B.Cu")
		(net "H_CPU1_NMI_LVC1_N")
	)
	(arc
		(start 101.489764 -227.969318)
		(mid 101.302566 -228.019461)
		(end 101.115368 -227.969318)
		(width 0.0889)
		(layer "B.Cu")
		(net "H_CPU1_NMI_LVC1_N")
	)
	(arc
		(start 101.996748 -227.939854)
		(mid 101.748243 -227.893888)
		(end 101.504496 -227.960682)
		(width 0.0889)
		(layer "B.Cu")
		(net "H_CPU1_NMI_LVC1_N")
	)
	(arc
		(start 90.777568 -227.969318)
		(mid 90.503339 -227.893393)
		(end 90.226896 -227.960682)
		(width 0.0889)
		(layer "B.Cu")
		(net "H_CPU1_NMI_LVC1_N")
	)
	(arc
		(start 89.837768 -227.969318)
		(mid 89.563539 -227.893393)
		(end 89.287096 -227.960682)
		(width 0.0889)
		(layer "B.Cu")
		(net "H_CPU1_NMI_LVC1_N")
	)
	(arc
		(start 100.549964 -227.969318)
		(mid 100.362766 -228.019461)
		(end 100.175568 -227.969318)
		(width 0.0889)
		(layer "B.Cu")
		(net "H_CPU1_NMI_LVC1_N")
	)
	(arc
		(start 99.60991 -227.969318)
		(mid 99.422712 -228.019461)
		(end 99.235514 -227.969318)
		(width 0.0889)
		(layer "B.Cu")
		(net "H_CPU1_NMI_LVC1_N")
	)
	(arc
		(start 96.790764 -227.969318)
		(mid 96.603566 -228.019461)
		(end 96.416368 -227.969318)
		(width 0.0889)
		(layer "B.Cu")
		(net "H_CPU1_NMI_LVC1_N")
	)
	(arc
		(start 99.235514 -227.969318)
		(mid 98.958955 -227.893609)
		(end 98.680778 -227.963222)
		(width 0.0889)
		(layer "B.Cu")
		(net "H_CPU1_NMI_LVC1_N")
	)
	(arc
		(start 100.175568 -227.969318)
		(mid 99.898755 -227.893482)
		(end 99.620324 -227.963222)
		(width 0.0889)
		(layer "B.Cu")
		(net "H_CPU1_NMI_LVC1_N")
	)
	(arc
		(start 91.7067 -227.963222)
		(mid 91.428522 -227.89353)
		(end 91.151964 -227.969318)
		(width 0.0889)
		(layer "B.Cu")
		(net "H_CPU1_NMI_LVC1_N")
	)
	(arc
		(start 93.596968 -227.969318)
		(mid 93.322739 -227.893393)
		(end 93.046296 -227.960682)
		(width 0.0889)
		(layer "B.Cu")
		(net "H_CPU1_NMI_LVC1_N")
	)
	(arc
		(start 93.971364 -227.969318)
		(mid 93.784166 -228.019461)
		(end 93.596968 -227.969318)
		(width 0.0889)
		(layer "B.Cu")
		(net "H_CPU1_NMI_LVC1_N")
	)
	(arc
		(start 95.476568 -227.969318)
		(mid 95.202339 -227.893393)
		(end 94.925896 -227.960682)
		(width 0.0889)
		(layer "B.Cu")
		(net "H_CPU1_NMI_LVC1_N")
	)
	(arc
		(start 98.670364 -227.969318)
		(mid 98.483166 -228.019461)
		(end 98.295968 -227.969318)
		(width 0.0889)
		(layer "B.Cu")
		(net "H_CPU1_NMI_LVC1_N")
	)
	(arc
		(start 88.897968 -227.969318)
		(mid 88.623739 -227.893393)
		(end 88.347296 -227.960682)
		(width 0.0889)
		(layer "B.Cu")
		(net "H_CPU1_NMI_LVC1_N")
	)
	(arc
		(start 87.39251 -227.969318)
		(mid 87.302152 -228.007221)
		(end 87.205058 -228.020372)
		(width 0.0889)
		(layer "B.Cu")
		(net "H_CPU1_NMI_LVC1_N")
	)
	(arc
		(start 89.272364 -227.969318)
		(mid 89.085166 -228.019461)
		(end 88.897968 -227.969318)
		(width 0.0889)
		(layer "B.Cu")
		(net "H_CPU1_NMI_LVC1_N")
	)
	(arc
		(start 87.947754 -227.963222)
		(mid 87.669322 -227.893408)
		(end 87.39251 -227.969318)
		(width 0.0889)
		(layer "B.Cu")
		(net "H_CPU1_NMI_LVC1_N")
	)
	(arc
		(start 93.031564 -227.969318)
		(mid 92.844366 -228.019461)
		(end 92.657168 -227.969318)
		(width 0.0889)
		(layer "B.Cu")
		(net "H_CPU1_NMI_LVC1_N")
	)
	(arc
		(start 94.536768 -227.969318)
		(mid 94.262539 -227.893393)
		(end 93.986096 -227.960682)
		(width 0.0889)
		(layer "B.Cu")
		(net "H_CPU1_NMI_LVC1_N")
	)
	(arc
		(start 96.416368 -227.969318)
		(mid 96.142139 -227.893393)
		(end 95.865696 -227.960682)
		(width 0.0889)
		(layer "B.Cu")
		(net "H_CPU1_NMI_LVC1_N")
	)
	(arc
		(start 95.850964 -227.969318)
		(mid 95.663766 -228.019461)
		(end 95.476568 -227.969318)
		(width 0.0889)
		(layer "B.Cu")
		(net "H_CPU1_NMI_LVC1_N")
	)
	(segment
		(start 102.242112 -233.064304)
		(end 102.242112 -232.528618)
		(width 0.12954)
		(layer "F.Cu")
		(net "H_CPU1_MEMTRIP_LVC1_R_N")
	)
	(segment
		(start 132.51688 -99.767898)
		(end 133.53288 -99.767898)
		(width 0.12954)
		(layer "F.Cu")
		(net "H_CPU1_MEMTRIP_LVC1_R_N")
	)
	(segment
		(start 102.242112 -232.528618)
		(end 102.242366 -232.528364)
		(width 0.12954)
		(layer "F.Cu")
		(net "H_CPU1_MEMTRIP_LVC1_R_N")
	)
	(segment
		(start 133.53288 -99.767898)
		(end 133.53288 -99.151948)
		(width 0.12954)
		(layer "F.Cu")
		(net "H_CPU1_MEMTRIP_LVC1_R_N")
	)
	(via
		(at 136.58342 -146.66976)
		(size 0.508)
		(drill 0.254)
		(layers "F.Cu" "B.Cu")
		(net "H_CPU1_MEMTRIP_LVC1_R_N")
	)
	(via
		(at 133.53288 -99.151948)
		(size 0.508)
		(drill 0.254)
		(layers "F.Cu" "B.Cu")
		(net "H_CPU1_MEMTRIP_LVC1_R_N")
	)
	(via
		(at 102.242366 -232.528364)
		(size 0.4572)
		(drill 0.2032)
		(layers "F.Cu" "B.Cu")
		(net "H_CPU1_MEMTRIP_LVC1_R_N")
	)
	(via
		(at 73.96861 -198.829168)
		(size 0.6604)
		(drill 0.3302)
		(layers "F.Cu" "B.Cu")
		(net "H_CPU1_MEMTRIP_LVC1_R_N")
	)
	(segment
		(start 70.09892 -204.429868)
		(end 70.09892 -205.918816)
		(width 0.12954)
		(layer "B.Cu")
		(net "H_CPU1_MEMTRIP_LVC1_R_N")
	)
	(segment
		(start 96.790764 -232.204006)
		(end 96.805496 -232.212642)
		(width 0.0889)
		(layer "B.Cu")
		(net "H_CPU1_MEMTRIP_LVC1_R_N")
	)
	(segment
		(start 73.96861 -194.123564)
		(end 75.973178 -192.118996)
		(width 0.12954)
		(layer "B.Cu")
		(net "H_CPU1_MEMTRIP_LVC1_R_N")
	)
	(segment
		(start 68.979796 -207.03794)
		(end 68.979796 -220.79839)
		(width 0.12954)
		(layer "B.Cu")
		(net "H_CPU1_MEMTRIP_LVC1_R_N")
	)
	(segment
		(start 85.127592 -232.153968)
		(end 86.265766 -232.153968)
		(width 0.0889)
		(layer "B.Cu")
		(net "H_CPU1_MEMTRIP_LVC1_R_N")
	)
	(segment
		(start 75.13955 -182.851298)
		(end 75.13955 -181.398672)
		(width 0.12954)
		(layer "B.Cu")
		(net "H_CPU1_MEMTRIP_LVC1_R_N")
	)
	(segment
		(start 75.973178 -190.03518)
		(end 74.785728 -187.168536)
		(width 0.12954)
		(layer "B.Cu")
		(net "H_CPU1_MEMTRIP_LVC1_R_N")
	)
	(segment
		(start 83.852258 -232.90657)
		(end 84.627974 -232.90657)
		(width 0.0889)
		(layer "B.Cu")
		(net "H_CPU1_MEMTRIP_LVC1_R_N")
	)
	(segment
		(start 72.456548 -202.07224)
		(end 70.09892 -204.429868)
		(width 0.12954)
		(layer "B.Cu")
		(net "H_CPU1_MEMTRIP_LVC1_R_N")
	)
	(segment
		(start 98.67011 -232.204006)
		(end 98.678238 -232.208832)
		(width 0.0889)
		(layer "B.Cu")
		(net "H_CPU1_MEMTRIP_LVC1_R_N")
	)
	(segment
		(start 75.973178 -192.118996)
		(end 75.973178 -190.03518)
		(width 0.12954)
		(layer "B.Cu")
		(net "H_CPU1_MEMTRIP_LVC1_R_N")
	)
	(segment
		(start 85.127084 -232.15346)
		(end 85.127592 -232.153968)
		(width 0.0889)
		(layer "B.Cu")
		(net "H_CPU1_MEMTRIP_LVC1_R_N")
	)
	(segment
		(start 73.96861 -198.829168)
		(end 73.96861 -199.439784)
		(width 0.12954)
		(layer "B.Cu")
		(net "H_CPU1_MEMTRIP_LVC1_R_N")
	)
	(segment
		(start 74.785728 -187.168536)
		(end 74.785728 -183.20512)
		(width 0.12954)
		(layer "B.Cu")
		(net "H_CPU1_MEMTRIP_LVC1_R_N")
	)
	(segment
		(start 102.085902 -232.257346)
		(end 102.181914 -232.423462)
		(width 0.0889)
		(layer "B.Cu")
		(net "H_CPU1_MEMTRIP_LVC1_R_N")
	)
	(segment
		(start 97.730564 -232.204006)
		(end 97.740978 -232.210102)
		(width 0.0889)
		(layer "B.Cu")
		(net "H_CPU1_MEMTRIP_LVC1_R_N")
	)
	(segment
		(start 72.456548 -200.951846)
		(end 72.456548 -202.07224)
		(width 0.12954)
		(layer "B.Cu")
		(net "H_CPU1_MEMTRIP_LVC1_R_N")
	)
	(segment
		(start 94.911164 -232.204006)
		(end 94.925896 -232.212642)
		(width 0.0889)
		(layer "B.Cu")
		(net "H_CPU1_MEMTRIP_LVC1_R_N")
	)
	(segment
		(start 84.905088 -232.629456)
		(end 84.905088 -232.375456)
		(width 0.0889)
		(layer "B.Cu")
		(net "H_CPU1_MEMTRIP_LVC1_R_N")
	)
	(segment
		(start 84.905088 -232.375456)
		(end 85.127084 -232.15346)
		(width 0.0889)
		(layer "B.Cu")
		(net "H_CPU1_MEMTRIP_LVC1_R_N")
	)
	(segment
		(start 101.996748 -232.23347)
		(end 102.085902 -232.257346)
		(width 0.0889)
		(layer "B.Cu")
		(net "H_CPU1_MEMTRIP_LVC1_R_N")
	)
	(segment
		(start 80.251046 -176.840642)
		(end 80.251046 -174.714154)
		(width 0.12954)
		(layer "B.Cu")
		(net "H_CPU1_MEMTRIP_LVC1_R_N")
	)
	(segment
		(start 98.678238 -232.208832)
		(end 98.680524 -232.210102)
		(width 0.0889)
		(layer "B.Cu")
		(net "H_CPU1_MEMTRIP_LVC1_R_N")
	)
	(segment
		(start 101.489764 -232.204006)
		(end 101.504496 -232.212642)
		(width 0.0889)
		(layer "B.Cu")
		(net "H_CPU1_MEMTRIP_LVC1_R_N")
	)
	(segment
		(start 92.09151 -232.204006)
		(end 92.101924 -232.210102)
		(width 0.0889)
		(layer "B.Cu")
		(net "H_CPU1_MEMTRIP_LVC1_R_N")
	)
	(segment
		(start 102.181914 -232.423462)
		(end 102.242366 -232.528364)
		(width 0.0889)
		(layer "B.Cu")
		(net "H_CPU1_MEMTRIP_LVC1_R_N")
	)
	(segment
		(start 76.049632 -180.48859)
		(end 76.603098 -180.48859)
		(width 0.12954)
		(layer "B.Cu")
		(net "H_CPU1_MEMTRIP_LVC1_R_N")
	)
	(segment
		(start 70.298818 -222.117412)
		(end 70.298818 -225.043746)
		(width 0.12954)
		(layer "B.Cu")
		(net "H_CPU1_MEMTRIP_LVC1_R_N")
	)
	(segment
		(start 88.332564 -232.204006)
		(end 88.347296 -232.212642)
		(width 0.0889)
		(layer "B.Cu")
		(net "H_CPU1_MEMTRIP_LVC1_R_N")
	)
	(segment
		(start 108.29544 -146.66976)
		(end 136.58342 -146.66976)
		(width 0.12954)
		(layer "B.Cu")
		(net "H_CPU1_MEMTRIP_LVC1_R_N")
	)
	(segment
		(start 78.161642 -232.90657)
		(end 83.852258 -232.90657)
		(width 0.12954)
		(layer "B.Cu")
		(net "H_CPU1_MEMTRIP_LVC1_R_N")
	)
	(segment
		(start 68.979796 -220.79839)
		(end 70.298818 -222.117412)
		(width 0.12954)
		(layer "B.Cu")
		(net "H_CPU1_MEMTRIP_LVC1_R_N")
	)
	(segment
		(start 73.96861 -198.829168)
		(end 73.96861 -194.123564)
		(width 0.12954)
		(layer "B.Cu")
		(net "H_CPU1_MEMTRIP_LVC1_R_N")
	)
	(segment
		(start 75.13955 -181.398672)
		(end 76.049632 -180.48859)
		(width 0.12954)
		(layer "B.Cu")
		(net "H_CPU1_MEMTRIP_LVC1_R_N")
	)
	(segment
		(start 70.298818 -225.043746)
		(end 78.161642 -232.90657)
		(width 0.12954)
		(layer "B.Cu")
		(net "H_CPU1_MEMTRIP_LVC1_R_N")
	)
	(segment
		(start 90.212164 -232.204006)
		(end 90.226896 -232.212642)
		(width 0.0889)
		(layer "B.Cu")
		(net "H_CPU1_MEMTRIP_LVC1_R_N")
	)
	(segment
		(start 80.251046 -174.714154)
		(end 108.29544 -146.66976)
		(width 0.12954)
		(layer "B.Cu")
		(net "H_CPU1_MEMTRIP_LVC1_R_N")
	)
	(segment
		(start 76.603098 -180.48859)
		(end 80.251046 -176.840642)
		(width 0.12954)
		(layer "B.Cu")
		(net "H_CPU1_MEMTRIP_LVC1_R_N")
	)
	(segment
		(start 95.850964 -232.204006)
		(end 95.865696 -232.212642)
		(width 0.0889)
		(layer "B.Cu")
		(net "H_CPU1_MEMTRIP_LVC1_R_N")
	)
	(segment
		(start 73.96861 -199.439784)
		(end 72.456548 -200.951846)
		(width 0.12954)
		(layer "B.Cu")
		(net "H_CPU1_MEMTRIP_LVC1_R_N")
	)
	(segment
		(start 84.627974 -232.90657)
		(end 84.905088 -232.629456)
		(width 0.0889)
		(layer "B.Cu")
		(net "H_CPU1_MEMTRIP_LVC1_R_N")
	)
	(segment
		(start 91.151964 -232.204006)
		(end 91.162378 -232.210102)
		(width 0.0889)
		(layer "B.Cu")
		(net "H_CPU1_MEMTRIP_LVC1_R_N")
	)
	(segment
		(start 93.031564 -232.204006)
		(end 93.046296 -232.212642)
		(width 0.0889)
		(layer "B.Cu")
		(net "H_CPU1_MEMTRIP_LVC1_R_N")
	)
	(segment
		(start 89.272364 -232.204006)
		(end 89.287096 -232.212642)
		(width 0.0889)
		(layer "B.Cu")
		(net "H_CPU1_MEMTRIP_LVC1_R_N")
	)
	(segment
		(start 99.610164 -232.204006)
		(end 99.624896 -232.212642)
		(width 0.0889)
		(layer "B.Cu")
		(net "H_CPU1_MEMTRIP_LVC1_R_N")
	)
	(segment
		(start 70.09892 -205.918816)
		(end 68.979796 -207.03794)
		(width 0.12954)
		(layer "B.Cu")
		(net "H_CPU1_MEMTRIP_LVC1_R_N")
	)
	(segment
		(start 74.785728 -183.20512)
		(end 75.13955 -182.851298)
		(width 0.12954)
		(layer "B.Cu")
		(net "H_CPU1_MEMTRIP_LVC1_R_N")
	)
	(arc
		(start 86.265766 -232.153968)
		(mid 86.362663 -232.166656)
		(end 86.452964 -232.204006)
		(width 0.0889)
		(layer "B.Cu")
		(net "H_CPU1_MEMTRIP_LVC1_R_N")
	)
	(arc
		(start 90.777568 -232.204006)
		(mid 90.964766 -232.153863)
		(end 91.151964 -232.204006)
		(width 0.0889)
		(layer "B.Cu")
		(net "H_CPU1_MEMTRIP_LVC1_R_N")
	)
	(arc
		(start 92.657168 -232.204006)
		(mid 92.844366 -232.153863)
		(end 93.031564 -232.204006)
		(width 0.0889)
		(layer "B.Cu")
		(net "H_CPU1_MEMTRIP_LVC1_R_N")
	)
	(arc
		(start 91.162378 -232.210102)
		(mid 91.440556 -232.279825)
		(end 91.717114 -232.204006)
		(width 0.0889)
		(layer "B.Cu")
		(net "H_CPU1_MEMTRIP_LVC1_R_N")
	)
	(arc
		(start 86.452964 -232.204006)
		(mid 86.735666 -232.279782)
		(end 87.018368 -232.204006)
		(width 0.0889)
		(layer "B.Cu")
		(net "H_CPU1_MEMTRIP_LVC1_R_N")
	)
	(arc
		(start 91.717114 -232.204006)
		(mid 91.904312 -232.153863)
		(end 92.09151 -232.204006)
		(width 0.0889)
		(layer "B.Cu")
		(net "H_CPU1_MEMTRIP_LVC1_R_N")
	)
	(arc
		(start 87.958168 -232.204006)
		(mid 88.145366 -232.153863)
		(end 88.332564 -232.204006)
		(width 0.0889)
		(layer "B.Cu")
		(net "H_CPU1_MEMTRIP_LVC1_R_N")
	)
	(arc
		(start 87.392764 -232.204006)
		(mid 87.675466 -232.279782)
		(end 87.958168 -232.204006)
		(width 0.0889)
		(layer "B.Cu")
		(net "H_CPU1_MEMTRIP_LVC1_R_N")
	)
	(arc
		(start 101.504496 -232.212642)
		(mid 101.74824 -232.279521)
		(end 101.996748 -232.23347)
		(width 0.0889)
		(layer "B.Cu")
		(net "H_CPU1_MEMTRIP_LVC1_R_N")
	)
	(arc
		(start 98.680524 -232.210102)
		(mid 98.958956 -232.279948)
		(end 99.235768 -232.204006)
		(width 0.0889)
		(layer "B.Cu")
		(net "H_CPU1_MEMTRIP_LVC1_R_N")
	)
	(arc
		(start 92.101924 -232.210102)
		(mid 92.380356 -232.279948)
		(end 92.657168 -232.204006)
		(width 0.0889)
		(layer "B.Cu")
		(net "H_CPU1_MEMTRIP_LVC1_R_N")
	)
	(arc
		(start 90.226896 -232.212642)
		(mid 90.503371 -232.279962)
		(end 90.777568 -232.204006)
		(width 0.0889)
		(layer "B.Cu")
		(net "H_CPU1_MEMTRIP_LVC1_R_N")
	)
	(arc
		(start 89.837768 -232.204006)
		(mid 90.024966 -232.153863)
		(end 90.212164 -232.204006)
		(width 0.0889)
		(layer "B.Cu")
		(net "H_CPU1_MEMTRIP_LVC1_R_N")
	)
	(arc
		(start 93.971364 -232.204006)
		(mid 94.254066 -232.279782)
		(end 94.536768 -232.204006)
		(width 0.0889)
		(layer "B.Cu")
		(net "H_CPU1_MEMTRIP_LVC1_R_N")
	)
	(arc
		(start 87.018368 -232.204006)
		(mid 87.205566 -232.153863)
		(end 87.392764 -232.204006)
		(width 0.0889)
		(layer "B.Cu")
		(net "H_CPU1_MEMTRIP_LVC1_R_N")
	)
	(arc
		(start 100.175568 -232.204006)
		(mid 100.362766 -232.153863)
		(end 100.549964 -232.204006)
		(width 0.0889)
		(layer "B.Cu")
		(net "H_CPU1_MEMTRIP_LVC1_R_N")
	)
	(arc
		(start 101.115368 -232.204006)
		(mid 101.302566 -232.153863)
		(end 101.489764 -232.204006)
		(width 0.0889)
		(layer "B.Cu")
		(net "H_CPU1_MEMTRIP_LVC1_R_N")
	)
	(arc
		(start 97.740978 -232.210102)
		(mid 98.019156 -232.279825)
		(end 98.295714 -232.204006)
		(width 0.0889)
		(layer "B.Cu")
		(net "H_CPU1_MEMTRIP_LVC1_R_N")
	)
	(arc
		(start 99.235768 -232.204006)
		(mid 99.422966 -232.153863)
		(end 99.610164 -232.204006)
		(width 0.0889)
		(layer "B.Cu")
		(net "H_CPU1_MEMTRIP_LVC1_R_N")
	)
	(arc
		(start 99.624896 -232.212642)
		(mid 99.901371 -232.279962)
		(end 100.175568 -232.204006)
		(width 0.0889)
		(layer "B.Cu")
		(net "H_CPU1_MEMTRIP_LVC1_R_N")
	)
	(arc
		(start 94.536768 -232.204006)
		(mid 94.723966 -232.153863)
		(end 94.911164 -232.204006)
		(width 0.0889)
		(layer "B.Cu")
		(net "H_CPU1_MEMTRIP_LVC1_R_N")
	)
	(arc
		(start 88.897968 -232.204006)
		(mid 89.085166 -232.153863)
		(end 89.272364 -232.204006)
		(width 0.0889)
		(layer "B.Cu")
		(net "H_CPU1_MEMTRIP_LVC1_R_N")
	)
	(arc
		(start 88.347296 -232.212642)
		(mid 88.623771 -232.279962)
		(end 88.897968 -232.204006)
		(width 0.0889)
		(layer "B.Cu")
		(net "H_CPU1_MEMTRIP_LVC1_R_N")
	)
	(arc
		(start 94.925896 -232.212642)
		(mid 95.202371 -232.279962)
		(end 95.476568 -232.204006)
		(width 0.0889)
		(layer "B.Cu")
		(net "H_CPU1_MEMTRIP_LVC1_R_N")
	)
	(arc
		(start 93.596968 -232.204006)
		(mid 93.784166 -232.153863)
		(end 93.971364 -232.204006)
		(width 0.0889)
		(layer "B.Cu")
		(net "H_CPU1_MEMTRIP_LVC1_R_N")
	)
	(arc
		(start 96.416368 -232.204006)
		(mid 96.603566 -232.153863)
		(end 96.790764 -232.204006)
		(width 0.0889)
		(layer "B.Cu")
		(net "H_CPU1_MEMTRIP_LVC1_R_N")
	)
	(arc
		(start 89.287096 -232.212642)
		(mid 89.563571 -232.279962)
		(end 89.837768 -232.204006)
		(width 0.0889)
		(layer "B.Cu")
		(net "H_CPU1_MEMTRIP_LVC1_R_N")
	)
	(arc
		(start 96.805496 -232.212642)
		(mid 97.081971 -232.279962)
		(end 97.356168 -232.204006)
		(width 0.0889)
		(layer "B.Cu")
		(net "H_CPU1_MEMTRIP_LVC1_R_N")
	)
	(arc
		(start 95.476568 -232.204006)
		(mid 95.663766 -232.153863)
		(end 95.850964 -232.204006)
		(width 0.0889)
		(layer "B.Cu")
		(net "H_CPU1_MEMTRIP_LVC1_R_N")
	)
	(arc
		(start 100.549964 -232.204006)
		(mid 100.832666 -232.279782)
		(end 101.115368 -232.204006)
		(width 0.0889)
		(layer "B.Cu")
		(net "H_CPU1_MEMTRIP_LVC1_R_N")
	)
	(arc
		(start 97.356168 -232.204006)
		(mid 97.543366 -232.153863)
		(end 97.730564 -232.204006)
		(width 0.0889)
		(layer "B.Cu")
		(net "H_CPU1_MEMTRIP_LVC1_R_N")
	)
	(arc
		(start 95.865696 -232.212642)
		(mid 96.142171 -232.279962)
		(end 96.416368 -232.204006)
		(width 0.0889)
		(layer "B.Cu")
		(net "H_CPU1_MEMTRIP_LVC1_R_N")
	)
	(arc
		(start 93.046296 -232.212642)
		(mid 93.322771 -232.279962)
		(end 93.596968 -232.204006)
		(width 0.0889)
		(layer "B.Cu")
		(net "H_CPU1_MEMTRIP_LVC1_R_N")
	)
	(arc
		(start 98.295714 -232.204006)
		(mid 98.482912 -232.153863)
		(end 98.67011 -232.204006)
		(width 0.0889)
		(layer "B.Cu")
		(net "H_CPU1_MEMTRIP_LVC1_R_N")
	)
	(segment
		(start 136.58342 -143.025368)
		(end 137.21334 -142.395448)
		(width 0.127)
		(layer "In2.Cu")
		(net "H_CPU1_MEMTRIP_LVC1_R_N")
	)
	(segment
		(start 136.58342 -146.66976)
		(end 136.58342 -143.025368)
		(width 0.127)
		(layer "In2.Cu")
		(net "H_CPU1_MEMTRIP_LVC1_R_N")
	)
	(segment
		(start 137.21334 -116.482368)
		(end 136.1186 -115.387628)
		(width 0.127)
		(layer "In2.Cu")
		(net "H_CPU1_MEMTRIP_LVC1_R_N")
	)
	(segment
		(start 137.21334 -142.395448)
		(end 137.21334 -116.482368)
		(width 0.127)
		(layer "In2.Cu")
		(net "H_CPU1_MEMTRIP_LVC1_R_N")
	)
	(segment
		(start 136.1186 -115.387628)
		(end 136.1186 -101.737668)
		(width 0.127)
		(layer "In2.Cu")
		(net "H_CPU1_MEMTRIP_LVC1_R_N")
	)
	(segment
		(start 136.1186 -101.737668)
		(end 133.53288 -99.151948)
		(width 0.127)
		(layer "In2.Cu")
		(net "H_CPU1_MEMTRIP_LVC1_R_N")
	)
	(segment
		(start 182.55488 -97.000568)
		(end 181.79288 -97.762568)
		(width 0.12954)
		(layer "F.Cu")
		(net "H_CPU1_MEMTRIP_LVC1_N")
	)
	(segment
		(start 181.79288 -97.762568)
		(end 181.79288 -100.574094)
		(width 0.12954)
		(layer "F.Cu")
		(net "H_CPU1_MEMTRIP_LVC1_N")
	)
	(segment
		(start 136.41705 -99.767898)
		(end 135.56488 -99.767898)
		(width 0.12954)
		(layer "F.Cu")
		(net "H_CPU1_MEMTRIP_LVC1_N")
	)
	(segment
		(start 133.85292 -81.935828)
		(end 136.78535 -84.868258)
		(width 0.12954)
		(layer "F.Cu")
		(net "H_CPU1_MEMTRIP_LVC1_N")
	)
	(segment
		(start 182.28183 -101.063044)
		(end 182.28183 -104.301544)
		(width 0.12954)
		(layer "F.Cu")
		(net "H_CPU1_MEMTRIP_LVC1_N")
	)
	(segment
		(start 182.28183 -104.301544)
		(end 182.955692 -104.975406)
		(width 0.12954)
		(layer "F.Cu")
		(net "H_CPU1_MEMTRIP_LVC1_N")
	)
	(segment
		(start 181.79288 -100.574094)
		(end 182.28183 -101.063044)
		(width 0.12954)
		(layer "F.Cu")
		(net "H_CPU1_MEMTRIP_LVC1_N")
	)
	(segment
		(start 136.78535 -99.399598)
		(end 136.41705 -99.767898)
		(width 0.12954)
		(layer "F.Cu")
		(net "H_CPU1_MEMTRIP_LVC1_N")
	)
	(segment
		(start 136.78535 -84.868258)
		(end 136.78535 -99.399598)
		(width 0.12954)
		(layer "F.Cu")
		(net "H_CPU1_MEMTRIP_LVC1_N")
	)
	(via
		(at 133.85292 -81.935828)
		(size 0.508)
		(drill 0.254)
		(layers "F.Cu" "B.Cu")
		(net "H_CPU1_MEMTRIP_LVC1_N")
	)
	(via
		(at 182.55488 -97.000568)
		(size 0.508)
		(drill 0.254)
		(layers "F.Cu" "B.Cu")
		(net "H_CPU1_MEMTRIP_LVC1_N")
	)
	(segment
		(start 178.6636 -92.633546)
		(end 180.330602 -94.300548)
		(width 0.127)
		(layer "In15.Cu")
		(net "H_CPU1_MEMTRIP_LVC1_N")
	)
	(segment
		(start 178.236626 -91.999308)
		(end 178.6636 -92.426282)
		(width 0.127)
		(layer "In15.Cu")
		(net "H_CPU1_MEMTRIP_LVC1_N")
	)
	(segment
		(start 154.822906 -93.3196)
		(end 171.081954 -93.3196)
		(width 0.127)
		(layer "In15.Cu")
		(net "H_CPU1_MEMTRIP_LVC1_N")
	)
	(segment
		(start 181.345586 -94.897448)
		(end 181.957218 -94.897448)
		(width 0.127)
		(layer "In15.Cu")
		(net "H_CPU1_MEMTRIP_LVC1_N")
	)
	(segment
		(start 180.330602 -94.300548)
		(end 180.748686 -94.300548)
		(width 0.127)
		(layer "In15.Cu")
		(net "H_CPU1_MEMTRIP_LVC1_N")
	)
	(segment
		(start 171.081954 -93.3196)
		(end 172.402246 -91.999308)
		(width 0.127)
		(layer "In15.Cu")
		(net "H_CPU1_MEMTRIP_LVC1_N")
	)
	(segment
		(start 145.370296 -83.86699)
		(end 154.822906 -93.3196)
		(width 0.127)
		(layer "In15.Cu")
		(net "H_CPU1_MEMTRIP_LVC1_N")
	)
	(segment
		(start 133.85292 -81.935828)
		(end 140.708126 -81.935828)
		(width 0.127)
		(layer "In15.Cu")
		(net "H_CPU1_MEMTRIP_LVC1_N")
	)
	(segment
		(start 182.55488 -95.49511)
		(end 182.55488 -97.000568)
		(width 0.127)
		(layer "In15.Cu")
		(net "H_CPU1_MEMTRIP_LVC1_N")
	)
	(segment
		(start 172.402246 -91.999308)
		(end 178.236626 -91.999308)
		(width 0.127)
		(layer "In15.Cu")
		(net "H_CPU1_MEMTRIP_LVC1_N")
	)
	(segment
		(start 178.6636 -92.426282)
		(end 178.6636 -92.633546)
		(width 0.127)
		(layer "In15.Cu")
		(net "H_CPU1_MEMTRIP_LVC1_N")
	)
	(segment
		(start 180.748686 -94.300548)
		(end 181.345586 -94.897448)
		(width 0.127)
		(layer "In15.Cu")
		(net "H_CPU1_MEMTRIP_LVC1_N")
	)
	(segment
		(start 181.957218 -94.897448)
		(end 182.55488 -95.49511)
		(width 0.127)
		(layer "In15.Cu")
		(net "H_CPU1_MEMTRIP_LVC1_N")
	)
	(segment
		(start 140.708126 -81.935828)
		(end 145.370296 -83.86699)
		(width 0.127)
		(layer "In15.Cu")
		(net "H_CPU1_MEMTRIP_LVC1_N")
	)
	(segment
		(start 115.399312 -234.69219)
		(end 115.399566 -234.691936)
		(width 0.12954)
		(layer "F.Cu")
		(net "H_CPU1_MEMHOT_OUT_LVC1_R_N")
	)
	(segment
		(start 115.399566 -234.691936)
		(end 115.399566 -234.15625)
		(width 0.12954)
		(layer "F.Cu")
		(net "H_CPU1_MEMHOT_OUT_LVC1_R_N")
	)
	(segment
		(start 134.04088 -92.274898)
		(end 133.02488 -92.274898)
		(width 0.12954)
		(layer "F.Cu")
		(net "H_CPU1_MEMHOT_OUT_LVC1_R_N")
	)
	(segment
		(start 134.04088 -91.658948)
		(end 134.04088 -92.274898)
		(width 0.12954)
		(layer "F.Cu")
		(net "H_CPU1_MEMHOT_OUT_LVC1_R_N")
	)
	(via
		(at 134.04088 -91.658948)
		(size 0.508)
		(drill 0.254)
		(layers "F.Cu" "B.Cu")
		(net "H_CPU1_MEMHOT_OUT_LVC1_R_N")
	)
	(via
		(at 152.503124 -224.164144)
		(size 0.6604)
		(drill 0.3302)
		(layers "F.Cu" "B.Cu")
		(net "H_CPU1_MEMHOT_OUT_LVC1_R_N")
	)
	(via
		(at 159.008318 -189.251082)
		(size 0.508)
		(drill 0.254)
		(layers "F.Cu" "B.Cu")
		(net "H_CPU1_MEMHOT_OUT_LVC1_R_N")
	)
	(via
		(at 115.399566 -234.15625)
		(size 0.4572)
		(drill 0.2032)
		(layers "F.Cu" "B.Cu")
		(net "H_CPU1_MEMHOT_OUT_LVC1_R_N")
	)
	(segment
		(start 124.059696 -232.844086)
		(end 124.044964 -232.852722)
		(width 0.0889)
		(layer "B.Cu")
		(net "H_CPU1_MEMHOT_OUT_LVC1_R_N")
	)
	(segment
		(start 158.9405 -191.597788)
		(end 158.9405 -194.137788)
		(width 0.12954)
		(layer "B.Cu")
		(net "H_CPU1_MEMHOT_OUT_LVC1_R_N")
	)
	(segment
		(start 137.992358 -232.75417)
		(end 137.237978 -232.75417)
		(width 0.12954)
		(layer "B.Cu")
		(net "H_CPU1_MEMHOT_OUT_LVC1_R_N")
	)
	(segment
		(start 157.78988 -189.624208)
		(end 157.78988 -190.447168)
		(width 0.12954)
		(layer "B.Cu")
		(net "H_CPU1_MEMHOT_OUT_LVC1_R_N")
	)
	(segment
		(start 126.489714 -232.852722)
		(end 126.4793 -232.846626)
		(width 0.0889)
		(layer "B.Cu")
		(net "H_CPU1_MEMHOT_OUT_LVC1_R_N")
	)
	(segment
		(start 117.466364 -232.852722)
		(end 117.460268 -232.856278)
		(width 0.0889)
		(layer "B.Cu")
		(net "H_CPU1_MEMHOT_OUT_LVC1_R_N")
	)
	(segment
		(start 117.481096 -232.844086)
		(end 117.466364 -232.852722)
		(width 0.0889)
		(layer "B.Cu")
		(net "H_CPU1_MEMHOT_OUT_LVC1_R_N")
	)
	(segment
		(start 152.503124 -224.164144)
		(end 150.011638 -226.65563)
		(width 0.12954)
		(layer "B.Cu")
		(net "H_CPU1_MEMHOT_OUT_LVC1_R_N")
	)
	(segment
		(start 116.621814 -233.666538)
		(end 116.607082 -233.657902)
		(width 0.0889)
		(layer "B.Cu")
		(net "H_CPU1_MEMHOT_OUT_LVC1_R_N")
	)
	(segment
		(start 127.818896 -232.844086)
		(end 127.804164 -232.852722)
		(width 0.0889)
		(layer "B.Cu")
		(net "H_CPU1_MEMHOT_OUT_LVC1_R_N")
	)
	(segment
		(start 150.011638 -229.07498)
		(end 146.243548 -232.84307)
		(width 0.12954)
		(layer "B.Cu")
		(net "H_CPU1_MEMHOT_OUT_LVC1_R_N")
	)
	(segment
		(start 131.578096 -232.844086)
		(end 131.563364 -232.852722)
		(width 0.0889)
		(layer "B.Cu")
		(net "H_CPU1_MEMHOT_OUT_LVC1_R_N")
	)
	(segment
		(start 134.008368 -232.852722)
		(end 133.997954 -232.846626)
		(width 0.0889)
		(layer "B.Cu")
		(net "H_CPU1_MEMHOT_OUT_LVC1_R_N")
	)
	(segment
		(start 159.008318 -189.251082)
		(end 158.972504 -189.215268)
		(width 0.12954)
		(layer "B.Cu")
		(net "H_CPU1_MEMHOT_OUT_LVC1_R_N")
	)
	(segment
		(start 120.295924 -232.846626)
		(end 120.28551 -232.852722)
		(width 0.0889)
		(layer "B.Cu")
		(net "H_CPU1_MEMHOT_OUT_LVC1_R_N")
	)
	(segment
		(start 156.856938 -197.38975)
		(end 156.303218 -197.38975)
		(width 0.12954)
		(layer "B.Cu")
		(net "H_CPU1_MEMHOT_OUT_LVC1_R_N")
	)
	(segment
		(start 119.356378 -232.846626)
		(end 119.345964 -232.852722)
		(width 0.0889)
		(layer "B.Cu")
		(net "H_CPU1_MEMHOT_OUT_LVC1_R_N")
	)
	(segment
		(start 117.0051 -233.661458)
		(end 116.99621 -233.666538)
		(width 0.0889)
		(layer "B.Cu")
		(net "H_CPU1_MEMHOT_OUT_LVC1_R_N")
	)
	(segment
		(start 158.19882 -189.215268)
		(end 157.78988 -189.624208)
		(width 0.12954)
		(layer "B.Cu")
		(net "H_CPU1_MEMHOT_OUT_LVC1_R_N")
	)
	(segment
		(start 154.26436 -222.402908)
		(end 152.503124 -224.164144)
		(width 0.12954)
		(layer "B.Cu")
		(net "H_CPU1_MEMHOT_OUT_LVC1_R_N")
	)
	(segment
		(start 122.180096 -232.844086)
		(end 122.165364 -232.852722)
		(width 0.0889)
		(layer "B.Cu")
		(net "H_CPU1_MEMHOT_OUT_LVC1_R_N")
	)
	(segment
		(start 133.068314 -232.852722)
		(end 133.0579 -232.846626)
		(width 0.0889)
		(layer "B.Cu")
		(net "H_CPU1_MEMHOT_OUT_LVC1_R_N")
	)
	(segment
		(start 140.527278 -232.84307)
		(end 140.148818 -233.22153)
		(width 0.12954)
		(layer "B.Cu")
		(net "H_CPU1_MEMHOT_OUT_LVC1_R_N")
	)
	(segment
		(start 156.303218 -197.38975)
		(end 154.26436 -199.428608)
		(width 0.12954)
		(layer "B.Cu")
		(net "H_CPU1_MEMHOT_OUT_LVC1_R_N")
	)
	(segment
		(start 126.874524 -232.846626)
		(end 126.86411 -232.852722)
		(width 0.0889)
		(layer "B.Cu")
		(net "H_CPU1_MEMHOT_OUT_LVC1_R_N")
	)
	(segment
		(start 146.243548 -232.84307)
		(end 140.527278 -232.84307)
		(width 0.12954)
		(layer "B.Cu")
		(net "H_CPU1_MEMHOT_OUT_LVC1_R_N")
	)
	(segment
		(start 115.656868 -234.15625)
		(end 115.399566 -234.15625)
		(width 0.0889)
		(layer "B.Cu")
		(net "H_CPU1_MEMHOT_OUT_LVC1_R_N")
	)
	(segment
		(start 137.237978 -232.75417)
		(end 136.63041 -232.75417)
		(width 0.0889)
		(layer "B.Cu")
		(net "H_CPU1_MEMHOT_OUT_LVC1_R_N")
	)
	(segment
		(start 154.26436 -199.428608)
		(end 154.26436 -222.402908)
		(width 0.12954)
		(layer "B.Cu")
		(net "H_CPU1_MEMHOT_OUT_LVC1_R_N")
	)
	(segment
		(start 158.162498 -194.91579)
		(end 158.162498 -196.08419)
		(width 0.12954)
		(layer "B.Cu")
		(net "H_CPU1_MEMHOT_OUT_LVC1_R_N")
	)
	(segment
		(start 118.420896 -232.844086)
		(end 118.406164 -232.852722)
		(width 0.0889)
		(layer "B.Cu")
		(net "H_CPU1_MEMHOT_OUT_LVC1_R_N")
	)
	(segment
		(start 123.119896 -232.844086)
		(end 123.105164 -232.852722)
		(width 0.0889)
		(layer "B.Cu")
		(net "H_CPU1_MEMHOT_OUT_LVC1_R_N")
	)
	(segment
		(start 138.459718 -233.22153)
		(end 137.992358 -232.75417)
		(width 0.12954)
		(layer "B.Cu")
		(net "H_CPU1_MEMHOT_OUT_LVC1_R_N")
	)
	(segment
		(start 116.23294 -233.627168)
		(end 115.737132 -234.122976)
		(width 0.0889)
		(layer "B.Cu")
		(net "H_CPU1_MEMHOT_OUT_LVC1_R_N")
	)
	(segment
		(start 128.758696 -232.844086)
		(end 128.743964 -232.852722)
		(width 0.0889)
		(layer "B.Cu")
		(net "H_CPU1_MEMHOT_OUT_LVC1_R_N")
	)
	(segment
		(start 157.78988 -190.447168)
		(end 158.9405 -191.597788)
		(width 0.12954)
		(layer "B.Cu")
		(net "H_CPU1_MEMHOT_OUT_LVC1_R_N")
	)
	(segment
		(start 124.999496 -232.844086)
		(end 124.984764 -232.852722)
		(width 0.0889)
		(layer "B.Cu")
		(net "H_CPU1_MEMHOT_OUT_LVC1_R_N")
	)
	(segment
		(start 130.638296 -232.844086)
		(end 130.623564 -232.852722)
		(width 0.0889)
		(layer "B.Cu")
		(net "H_CPU1_MEMHOT_OUT_LVC1_R_N")
	)
	(segment
		(start 158.972504 -189.215268)
		(end 158.19882 -189.215268)
		(width 0.12954)
		(layer "B.Cu")
		(net "H_CPU1_MEMHOT_OUT_LVC1_R_N")
	)
	(segment
		(start 158.162498 -196.08419)
		(end 156.856938 -197.38975)
		(width 0.12954)
		(layer "B.Cu")
		(net "H_CPU1_MEMHOT_OUT_LVC1_R_N")
	)
	(segment
		(start 140.148818 -233.22153)
		(end 138.459718 -233.22153)
		(width 0.12954)
		(layer "B.Cu")
		(net "H_CPU1_MEMHOT_OUT_LVC1_R_N")
	)
	(segment
		(start 129.698496 -232.844086)
		(end 129.683764 -232.852722)
		(width 0.0889)
		(layer "B.Cu")
		(net "H_CPU1_MEMHOT_OUT_LVC1_R_N")
	)
	(segment
		(start 158.9405 -194.137788)
		(end 158.162498 -194.91579)
		(width 0.12954)
		(layer "B.Cu")
		(net "H_CPU1_MEMHOT_OUT_LVC1_R_N")
	)
	(segment
		(start 150.011638 -226.65563)
		(end 150.011638 -229.07498)
		(width 0.12954)
		(layer "B.Cu")
		(net "H_CPU1_MEMHOT_OUT_LVC1_R_N")
	)
	(arc
		(start 131.188968 -232.852722)
		(mid 130.914769 -232.776887)
		(end 130.638296 -232.844086)
		(width 0.0889)
		(layer "B.Cu")
		(net "H_CPU1_MEMHOT_OUT_LVC1_R_N")
	)
	(arc
		(start 121.225564 -232.852722)
		(mid 121.038366 -232.902865)
		(end 120.851168 -232.852722)
		(width 0.0889)
		(layer "B.Cu")
		(net "H_CPU1_MEMHOT_OUT_LVC1_R_N")
	)
	(arc
		(start 133.0579 -232.846626)
		(mid 132.779722 -232.776903)
		(end 132.503164 -232.852722)
		(width 0.0889)
		(layer "B.Cu")
		(net "H_CPU1_MEMHOT_OUT_LVC1_R_N")
	)
	(arc
		(start 130.623564 -232.852722)
		(mid 130.436366 -232.902865)
		(end 130.249168 -232.852722)
		(width 0.0889)
		(layer "B.Cu")
		(net "H_CPU1_MEMHOT_OUT_LVC1_R_N")
	)
	(arc
		(start 127.804164 -232.852722)
		(mid 127.616966 -232.902865)
		(end 127.429768 -232.852722)
		(width 0.0889)
		(layer "B.Cu")
		(net "H_CPU1_MEMHOT_OUT_LVC1_R_N")
	)
	(arc
		(start 122.165364 -232.852722)
		(mid 121.978166 -232.902865)
		(end 121.790968 -232.852722)
		(width 0.0889)
		(layer "B.Cu")
		(net "H_CPU1_MEMHOT_OUT_LVC1_R_N")
	)
	(arc
		(start 134.382764 -232.852722)
		(mid 134.195566 -232.902865)
		(end 134.008368 -232.852722)
		(width 0.0889)
		(layer "B.Cu")
		(net "H_CPU1_MEMHOT_OUT_LVC1_R_N")
	)
	(arc
		(start 117.183662 -233.34218)
		(mid 117.135983 -233.52508)
		(end 117.0051 -233.661458)
		(width 0.0889)
		(layer "B.Cu")
		(net "H_CPU1_MEMHOT_OUT_LVC1_R_N")
	)
	(arc
		(start 120.851168 -232.852722)
		(mid 120.574355 -232.776852)
		(end 120.295924 -232.846626)
		(width 0.0889)
		(layer "B.Cu")
		(net "H_CPU1_MEMHOT_OUT_LVC1_R_N")
	)
	(arc
		(start 124.610368 -232.852722)
		(mid 124.336169 -232.776887)
		(end 124.059696 -232.844086)
		(width 0.0889)
		(layer "B.Cu")
		(net "H_CPU1_MEMHOT_OUT_LVC1_R_N")
	)
	(arc
		(start 128.369568 -232.852722)
		(mid 128.095369 -232.776887)
		(end 127.818896 -232.844086)
		(width 0.0889)
		(layer "B.Cu")
		(net "H_CPU1_MEMHOT_OUT_LVC1_R_N")
	)
	(arc
		(start 119.911114 -232.852722)
		(mid 119.634555 -232.776979)
		(end 119.356378 -232.846626)
		(width 0.0889)
		(layer "B.Cu")
		(net "H_CPU1_MEMHOT_OUT_LVC1_R_N")
	)
	(arc
		(start 117.460268 -232.856278)
		(mid 117.257681 -233.062629)
		(end 117.183662 -233.34218)
		(width 0.0889)
		(layer "B.Cu")
		(net "H_CPU1_MEMHOT_OUT_LVC1_R_N")
	)
	(arc
		(start 118.031768 -232.852722)
		(mid 117.757569 -232.776887)
		(end 117.481096 -232.844086)
		(width 0.0889)
		(layer "B.Cu")
		(net "H_CPU1_MEMHOT_OUT_LVC1_R_N")
	)
	(arc
		(start 125.924564 -232.852722)
		(mid 125.737366 -232.902865)
		(end 125.550168 -232.852722)
		(width 0.0889)
		(layer "B.Cu")
		(net "H_CPU1_MEMHOT_OUT_LVC1_R_N")
	)
	(arc
		(start 136.262364 -232.852722)
		(mid 136.075166 -232.902865)
		(end 135.887968 -232.852722)
		(width 0.0889)
		(layer "B.Cu")
		(net "H_CPU1_MEMHOT_OUT_LVC1_R_N")
	)
	(arc
		(start 116.607082 -233.657902)
		(mid 116.465289 -233.604738)
		(end 116.314474 -233.5911)
		(width 0.0889)
		(layer "B.Cu")
		(net "H_CPU1_MEMHOT_OUT_LVC1_R_N")
	)
	(arc
		(start 126.86411 -232.852722)
		(mid 126.676912 -232.902865)
		(end 126.489714 -232.852722)
		(width 0.0889)
		(layer "B.Cu")
		(net "H_CPU1_MEMHOT_OUT_LVC1_R_N")
	)
	(arc
		(start 133.997954 -232.846626)
		(mid 133.719522 -232.77678)
		(end 133.44271 -232.852722)
		(width 0.0889)
		(layer "B.Cu")
		(net "H_CPU1_MEMHOT_OUT_LVC1_R_N")
	)
	(arc
		(start 132.128768 -232.852722)
		(mid 131.854569 -232.776887)
		(end 131.578096 -232.844086)
		(width 0.0889)
		(layer "B.Cu")
		(net "H_CPU1_MEMHOT_OUT_LVC1_R_N")
	)
	(arc
		(start 131.563364 -232.852722)
		(mid 131.376166 -232.902865)
		(end 131.188968 -232.852722)
		(width 0.0889)
		(layer "B.Cu")
		(net "H_CPU1_MEMHOT_OUT_LVC1_R_N")
	)
	(arc
		(start 118.971568 -232.852722)
		(mid 118.697369 -232.776887)
		(end 118.420896 -232.844086)
		(width 0.0889)
		(layer "B.Cu")
		(net "H_CPU1_MEMHOT_OUT_LVC1_R_N")
	)
	(arc
		(start 124.044964 -232.852722)
		(mid 123.857766 -232.902865)
		(end 123.670568 -232.852722)
		(width 0.0889)
		(layer "B.Cu")
		(net "H_CPU1_MEMHOT_OUT_LVC1_R_N")
	)
	(arc
		(start 129.683764 -232.852722)
		(mid 129.496566 -232.902865)
		(end 129.309368 -232.852722)
		(width 0.0889)
		(layer "B.Cu")
		(net "H_CPU1_MEMHOT_OUT_LVC1_R_N")
	)
	(arc
		(start 126.4793 -232.846626)
		(mid 126.201122 -232.776903)
		(end 125.924564 -232.852722)
		(width 0.0889)
		(layer "B.Cu")
		(net "H_CPU1_MEMHOT_OUT_LVC1_R_N")
	)
	(arc
		(start 124.984764 -232.852722)
		(mid 124.797566 -232.902865)
		(end 124.610368 -232.852722)
		(width 0.0889)
		(layer "B.Cu")
		(net "H_CPU1_MEMHOT_OUT_LVC1_R_N")
	)
	(arc
		(start 127.429768 -232.852722)
		(mid 127.152955 -232.776852)
		(end 126.874524 -232.846626)
		(width 0.0889)
		(layer "B.Cu")
		(net "H_CPU1_MEMHOT_OUT_LVC1_R_N")
	)
	(arc
		(start 116.314474 -233.5911)
		(mid 116.270331 -233.601493)
		(end 116.23294 -233.627168)
		(width 0.0889)
		(layer "B.Cu")
		(net "H_CPU1_MEMHOT_OUT_LVC1_R_N")
	)
	(arc
		(start 118.406164 -232.852722)
		(mid 118.218966 -232.902865)
		(end 118.031768 -232.852722)
		(width 0.0889)
		(layer "B.Cu")
		(net "H_CPU1_MEMHOT_OUT_LVC1_R_N")
	)
	(arc
		(start 121.790968 -232.852722)
		(mid 121.508266 -232.776946)
		(end 121.225564 -232.852722)
		(width 0.0889)
		(layer "B.Cu")
		(net "H_CPU1_MEMHOT_OUT_LVC1_R_N")
	)
	(arc
		(start 115.737132 -234.122976)
		(mid 115.700321 -234.147636)
		(end 115.656868 -234.15625)
		(width 0.0889)
		(layer "B.Cu")
		(net "H_CPU1_MEMHOT_OUT_LVC1_R_N")
	)
	(arc
		(start 132.503164 -232.852722)
		(mid 132.315966 -232.902865)
		(end 132.128768 -232.852722)
		(width 0.0889)
		(layer "B.Cu")
		(net "H_CPU1_MEMHOT_OUT_LVC1_R_N")
	)
	(arc
		(start 119.345964 -232.852722)
		(mid 119.158766 -232.902865)
		(end 118.971568 -232.852722)
		(width 0.0889)
		(layer "B.Cu")
		(net "H_CPU1_MEMHOT_OUT_LVC1_R_N")
	)
	(arc
		(start 128.743964 -232.852722)
		(mid 128.556766 -232.902865)
		(end 128.369568 -232.852722)
		(width 0.0889)
		(layer "B.Cu")
		(net "H_CPU1_MEMHOT_OUT_LVC1_R_N")
	)
	(arc
		(start 134.948168 -232.852722)
		(mid 134.665466 -232.776946)
		(end 134.382764 -232.852722)
		(width 0.0889)
		(layer "B.Cu")
		(net "H_CPU1_MEMHOT_OUT_LVC1_R_N")
	)
	(arc
		(start 125.550168 -232.852722)
		(mid 125.275969 -232.776887)
		(end 124.999496 -232.844086)
		(width 0.0889)
		(layer "B.Cu")
		(net "H_CPU1_MEMHOT_OUT_LVC1_R_N")
	)
	(arc
		(start 116.99621 -233.666538)
		(mid 116.809012 -233.716681)
		(end 116.621814 -233.666538)
		(width 0.0889)
		(layer "B.Cu")
		(net "H_CPU1_MEMHOT_OUT_LVC1_R_N")
	)
	(arc
		(start 130.249168 -232.852722)
		(mid 129.974969 -232.776887)
		(end 129.698496 -232.844086)
		(width 0.0889)
		(layer "B.Cu")
		(net "H_CPU1_MEMHOT_OUT_LVC1_R_N")
	)
	(arc
		(start 136.63041 -232.75417)
		(mid 136.439911 -232.779247)
		(end 136.262364 -232.852722)
		(width 0.0889)
		(layer "B.Cu")
		(net "H_CPU1_MEMHOT_OUT_LVC1_R_N")
	)
	(arc
		(start 129.309368 -232.852722)
		(mid 129.035169 -232.776887)
		(end 128.758696 -232.844086)
		(width 0.0889)
		(layer "B.Cu")
		(net "H_CPU1_MEMHOT_OUT_LVC1_R_N")
	)
	(arc
		(start 135.887968 -232.852722)
		(mid 135.605266 -232.776946)
		(end 135.322564 -232.852722)
		(width 0.0889)
		(layer "B.Cu")
		(net "H_CPU1_MEMHOT_OUT_LVC1_R_N")
	)
	(arc
		(start 135.322564 -232.852722)
		(mid 135.135366 -232.902865)
		(end 134.948168 -232.852722)
		(width 0.0889)
		(layer "B.Cu")
		(net "H_CPU1_MEMHOT_OUT_LVC1_R_N")
	)
	(arc
		(start 123.105164 -232.852722)
		(mid 122.917966 -232.902865)
		(end 122.730768 -232.852722)
		(width 0.0889)
		(layer "B.Cu")
		(net "H_CPU1_MEMHOT_OUT_LVC1_R_N")
	)
	(arc
		(start 133.44271 -232.852722)
		(mid 133.255512 -232.902865)
		(end 133.068314 -232.852722)
		(width 0.0889)
		(layer "B.Cu")
		(net "H_CPU1_MEMHOT_OUT_LVC1_R_N")
	)
	(arc
		(start 122.730768 -232.852722)
		(mid 122.456569 -232.776887)
		(end 122.180096 -232.844086)
		(width 0.0889)
		(layer "B.Cu")
		(net "H_CPU1_MEMHOT_OUT_LVC1_R_N")
	)
	(arc
		(start 120.28551 -232.852722)
		(mid 120.098312 -232.902865)
		(end 119.911114 -232.852722)
		(width 0.0889)
		(layer "B.Cu")
		(net "H_CPU1_MEMHOT_OUT_LVC1_R_N")
	)
	(arc
		(start 123.670568 -232.852722)
		(mid 123.396369 -232.776887)
		(end 123.119896 -232.844086)
		(width 0.0889)
		(layer "B.Cu")
		(net "H_CPU1_MEMHOT_OUT_LVC1_R_N")
	)
	(segment
		(start 154.89047 -184.094882)
		(end 144.055338 -173.25975)
		(width 0.127)
		(layer "In2.Cu")
		(net "H_CPU1_MEMHOT_OUT_LVC1_R_N")
	)
	(segment
		(start 154.89047 -188.180218)
		(end 154.89047 -184.094882)
		(width 0.127)
		(layer "In2.Cu")
		(net "H_CPU1_MEMHOT_OUT_LVC1_R_N")
	)
	(segment
		(start 142.227046 -151.094948)
		(end 138.18616 -151.094948)
		(width 0.127)
		(layer "In2.Cu")
		(net "H_CPU1_MEMHOT_OUT_LVC1_R_N")
	)
	(segment
		(start 155.6512 -188.940948)
		(end 154.89047 -188.180218)
		(width 0.127)
		(layer "In2.Cu")
		(net "H_CPU1_MEMHOT_OUT_LVC1_R_N")
	)
	(segment
		(start 137.69594 -116.22786)
		(end 136.55802 -115.08994)
		(width 0.127)
		(layer "In2.Cu")
		(net "H_CPU1_MEMHOT_OUT_LVC1_R_N")
	)
	(segment
		(start 144.055338 -173.25975)
		(end 144.055338 -152.92324)
		(width 0.127)
		(layer "In2.Cu")
		(net "H_CPU1_MEMHOT_OUT_LVC1_R_N")
	)
	(segment
		(start 158.698184 -188.940948)
		(end 155.6512 -188.940948)
		(width 0.127)
		(layer "In2.Cu")
		(net "H_CPU1_MEMHOT_OUT_LVC1_R_N")
	)
	(segment
		(start 137.09904 -143.439388)
		(end 137.69594 -142.842488)
		(width 0.127)
		(layer "In2.Cu")
		(net "H_CPU1_MEMHOT_OUT_LVC1_R_N")
	)
	(segment
		(start 138.18616 -151.094948)
		(end 137.09904 -150.007828)
		(width 0.127)
		(layer "In2.Cu")
		(net "H_CPU1_MEMHOT_OUT_LVC1_R_N")
	)
	(segment
		(start 137.09904 -150.007828)
		(end 137.09904 -143.439388)
		(width 0.127)
		(layer "In2.Cu")
		(net "H_CPU1_MEMHOT_OUT_LVC1_R_N")
	)
	(segment
		(start 159.008318 -189.251082)
		(end 158.698184 -188.940948)
		(width 0.127)
		(layer "In2.Cu")
		(net "H_CPU1_MEMHOT_OUT_LVC1_R_N")
	)
	(segment
		(start 136.55802 -94.176088)
		(end 134.04088 -91.658948)
		(width 0.127)
		(layer "In2.Cu")
		(net "H_CPU1_MEMHOT_OUT_LVC1_R_N")
	)
	(segment
		(start 137.69594 -142.842488)
		(end 137.69594 -116.22786)
		(width 0.127)
		(layer "In2.Cu")
		(net "H_CPU1_MEMHOT_OUT_LVC1_R_N")
	)
	(segment
		(start 144.055338 -152.92324)
		(end 142.227046 -151.094948)
		(width 0.127)
		(layer "In2.Cu")
		(net "H_CPU1_MEMHOT_OUT_LVC1_R_N")
	)
	(segment
		(start 136.55802 -115.08994)
		(end 136.55802 -94.176088)
		(width 0.127)
		(layer "In2.Cu")
		(net "H_CPU1_MEMHOT_OUT_LVC1_R_N")
	)
	(segment
		(start 135.05688 -92.274898)
		(end 135.05688 -91.658948)
		(width 0.12954)
		(layer "F.Cu")
		(net "H_CPU1_MEMHOT_OUT_LVC1_N")
	)
	(segment
		(start 181.355746 -109.775498)
		(end 181.755796 -109.375448)
		(width 0.12954)
		(layer "F.Cu")
		(net "H_CPU1_MEMHOT_OUT_LVC1_N")
	)
	(via
		(at 181.755796 -109.375448)
		(size 0.4572)
		(drill 0.254)
		(layers "F.Cu" "B.Cu")
		(net "H_CPU1_MEMHOT_OUT_LVC1_N")
	)
	(via
		(at 135.05688 -91.658948)
		(size 0.508)
		(drill 0.254)
		(layers "F.Cu" "B.Cu")
		(net "H_CPU1_MEMHOT_OUT_LVC1_N")
	)
	(segment
		(start 164.76726 -100.853748)
		(end 165.58006 -101.666548)
		(width 0.127)
		(layer "In15.Cu")
		(net "H_CPU1_MEMHOT_OUT_LVC1_N")
	)
	(segment
		(start 176.3014 -106.07675)
		(end 176.79289 -106.56824)
		(width 0.127)
		(layer "In15.Cu")
		(net "H_CPU1_MEMHOT_OUT_LVC1_N")
	)
	(segment
		(start 142.19682 -95.961708)
		(end 147.08886 -100.853748)
		(width 0.127)
		(layer "In15.Cu")
		(net "H_CPU1_MEMHOT_OUT_LVC1_N")
	)
	(segment
		(start 177.362612 -106.826558)
		(end 177.362612 -108.738162)
		(width 0.127)
		(layer "In15.Cu")
		(net "H_CPU1_MEMHOT_OUT_LVC1_N")
	)
	(segment
		(start 179.43322 -109.776768)
		(end 181.11724 -109.776768)
		(width 0.127)
		(layer "In15.Cu")
		(net "H_CPU1_MEMHOT_OUT_LVC1_N")
	)
	(segment
		(start 177.104294 -106.56824)
		(end 177.362612 -106.826558)
		(width 0.127)
		(layer "In15.Cu")
		(net "H_CPU1_MEMHOT_OUT_LVC1_N")
	)
	(segment
		(start 166.0398 -101.666548)
		(end 166.57066 -102.197408)
		(width 0.127)
		(layer "In15.Cu")
		(net "H_CPU1_MEMHOT_OUT_LVC1_N")
	)
	(segment
		(start 178.624738 -108.968286)
		(end 179.43322 -109.776768)
		(width 0.127)
		(layer "In15.Cu")
		(net "H_CPU1_MEMHOT_OUT_LVC1_N")
	)
	(segment
		(start 175.34636 -104.07396)
		(end 176.3014 -105.029)
		(width 0.127)
		(layer "In15.Cu")
		(net "H_CPU1_MEMHOT_OUT_LVC1_N")
	)
	(segment
		(start 147.08886 -100.853748)
		(end 164.76726 -100.853748)
		(width 0.127)
		(layer "In15.Cu")
		(net "H_CPU1_MEMHOT_OUT_LVC1_N")
	)
	(segment
		(start 174.3583 -102.197408)
		(end 175.34636 -103.185468)
		(width 0.127)
		(layer "In15.Cu")
		(net "H_CPU1_MEMHOT_OUT_LVC1_N")
	)
	(segment
		(start 176.3014 -105.029)
		(end 176.3014 -106.07675)
		(width 0.127)
		(layer "In15.Cu")
		(net "H_CPU1_MEMHOT_OUT_LVC1_N")
	)
	(segment
		(start 175.34636 -103.185468)
		(end 175.34636 -104.07396)
		(width 0.127)
		(layer "In15.Cu")
		(net "H_CPU1_MEMHOT_OUT_LVC1_N")
	)
	(segment
		(start 181.51856 -109.375448)
		(end 181.755796 -109.375448)
		(width 0.127)
		(layer "In15.Cu")
		(net "H_CPU1_MEMHOT_OUT_LVC1_N")
	)
	(segment
		(start 177.362612 -108.738162)
		(end 177.592736 -108.968286)
		(width 0.127)
		(layer "In15.Cu")
		(net "H_CPU1_MEMHOT_OUT_LVC1_N")
	)
	(segment
		(start 181.11724 -109.776768)
		(end 181.51856 -109.375448)
		(width 0.127)
		(layer "In15.Cu")
		(net "H_CPU1_MEMHOT_OUT_LVC1_N")
	)
	(segment
		(start 166.57066 -102.197408)
		(end 174.3583 -102.197408)
		(width 0.127)
		(layer "In15.Cu")
		(net "H_CPU1_MEMHOT_OUT_LVC1_N")
	)
	(segment
		(start 165.58006 -101.666548)
		(end 166.0398 -101.666548)
		(width 0.127)
		(layer "In15.Cu")
		(net "H_CPU1_MEMHOT_OUT_LVC1_N")
	)
	(segment
		(start 139.35964 -95.961708)
		(end 142.19682 -95.961708)
		(width 0.127)
		(layer "In15.Cu")
		(net "H_CPU1_MEMHOT_OUT_LVC1_N")
	)
	(segment
		(start 135.05688 -91.658948)
		(end 139.35964 -95.961708)
		(width 0.127)
		(layer "In15.Cu")
		(net "H_CPU1_MEMHOT_OUT_LVC1_N")
	)
	(segment
		(start 177.592736 -108.968286)
		(end 178.624738 -108.968286)
		(width 0.127)
		(layer "In15.Cu")
		(net "H_CPU1_MEMHOT_OUT_LVC1_N")
	)
	(segment
		(start 176.79289 -106.56824)
		(end 177.104294 -106.56824)
		(width 0.127)
		(layer "In15.Cu")
		(net "H_CPU1_MEMHOT_OUT_LVC1_N")
	)
	(segment
		(start 197.01383 -101.145848)
		(end 196.40423 -101.145848)
		(width 0.12954)
		(layer "F.Cu")
		(net "H_CPU1_MEMHOT_IN_LVC1_R_N")
	)
	(segment
		(start 183.755538 -108.175552)
		(end 184.155588 -107.775502)
		(width 0.12954)
		(layer "F.Cu")
		(net "H_CPU1_MEMHOT_IN_LVC1_R_N")
	)
	(via
		(at 184.155588 -107.775502)
		(size 0.4572)
		(drill 0.254)
		(layers "F.Cu" "B.Cu")
		(net "H_CPU1_MEMHOT_IN_LVC1_R_N")
	)
	(via
		(at 196.40423 -101.145848)
		(size 0.508)
		(drill 0.254)
		(layers "F.Cu" "B.Cu")
		(net "H_CPU1_MEMHOT_IN_LVC1_R_N")
	)
	(segment
		(start 189.26556 -108.176568)
		(end 193.797428 -103.6447)
		(width 0.127)
		(layer "In6.Cu")
		(net "H_CPU1_MEMHOT_IN_LVC1_R_N")
	)
	(segment
		(start 184.155588 -107.775502)
		(end 184.556654 -108.176568)
		(width 0.127)
		(layer "In6.Cu")
		(net "H_CPU1_MEMHOT_IN_LVC1_R_N")
	)
	(segment
		(start 194.8942 -103.6447)
		(end 195.80352 -102.73538)
		(width 0.127)
		(layer "In6.Cu")
		(net "H_CPU1_MEMHOT_IN_LVC1_R_N")
	)
	(segment
		(start 193.797428 -103.6447)
		(end 194.8942 -103.6447)
		(width 0.127)
		(layer "In6.Cu")
		(net "H_CPU1_MEMHOT_IN_LVC1_R_N")
	)
	(segment
		(start 195.80352 -101.746558)
		(end 196.40423 -101.145848)
		(width 0.127)
		(layer "In6.Cu")
		(net "H_CPU1_MEMHOT_IN_LVC1_R_N")
	)
	(segment
		(start 184.556654 -108.176568)
		(end 189.26556 -108.176568)
		(width 0.127)
		(layer "In6.Cu")
		(net "H_CPU1_MEMHOT_IN_LVC1_R_N")
	)
	(segment
		(start 195.80352 -102.73538)
		(end 195.80352 -101.746558)
		(width 0.127)
		(layer "In6.Cu")
		(net "H_CPU1_MEMHOT_IN_LVC1_R_N")
	)
	(segment
		(start 101.772466 -230.622602)
		(end 101.772212 -230.622348)
		(width 0.12954)
		(layer "F.Cu")
		(net "H_CPU1_MEMHOT_IN_LVC1_N")
	)
	(segment
		(start 101.772212 -230.622348)
		(end 101.772212 -230.086662)
		(width 0.12954)
		(layer "F.Cu")
		(net "H_CPU1_MEMHOT_IN_LVC1_N")
	)
	(segment
		(start 201.42073 -99.939348)
		(end 202.06208 -99.939348)
		(width 0.12954)
		(layer "F.Cu")
		(net "H_CPU1_MEMHOT_IN_LVC1_N")
	)
	(via
		(at 145.27022 -106.992928)
		(size 0.508)
		(drill 0.254)
		(layers "F.Cu" "B.Cu")
		(net "H_CPU1_MEMHOT_IN_LVC1_N")
	)
	(via
		(at 101.772212 -230.086662)
		(size 0.4572)
		(drill 0.2032)
		(layers "F.Cu" "B.Cu")
		(net "H_CPU1_MEMHOT_IN_LVC1_N")
	)
	(via
		(at 79.727044 -229.749096)
		(size 0.6604)
		(drill 0.3302)
		(layers "F.Cu" "B.Cu")
		(net "H_CPU1_MEMHOT_IN_LVC1_N")
	)
	(via
		(at 141.43228 -144.897348)
		(size 0.508)
		(drill 0.254)
		(layers "F.Cu" "B.Cu")
		(net "H_CPU1_MEMHOT_IN_LVC1_N")
	)
	(via
		(at 202.06208 -99.939348)
		(size 0.508)
		(drill 0.254)
		(layers "F.Cu" "B.Cu")
		(net "H_CPU1_MEMHOT_IN_LVC1_N")
	)
	(segment
		(start 76.656438 -186.860434)
		(end 77.800962 -189.623954)
		(width 0.12954)
		(layer "B.Cu")
		(net "H_CPU1_MEMHOT_IN_LVC1_N")
	)
	(segment
		(start 101.907594 -230.435658)
		(end 101.928676 -230.35768)
		(width 0.0889)
		(layer "B.Cu")
		(net "H_CPU1_MEMHOT_IN_LVC1_N")
	)
	(segment
		(start 90.297254 -230.404924)
		(end 90.307668 -230.41102)
		(width 0.0889)
		(layer "B.Cu")
		(net "H_CPU1_MEMHOT_IN_LVC1_N")
	)
	(segment
		(start 94.991682 -230.402384)
		(end 95.006414 -230.41102)
		(width 0.0889)
		(layer "B.Cu")
		(net "H_CPU1_MEMHOT_IN_LVC1_N")
	)
	(segment
		(start 77.800962 -189.623954)
		(end 77.800962 -195.14566)
		(width 0.12954)
		(layer "B.Cu")
		(net "H_CPU1_MEMHOT_IN_LVC1_N")
	)
	(segment
		(start 77.310488 -184.1246)
		(end 76.656438 -184.77865)
		(width 0.12954)
		(layer "B.Cu")
		(net "H_CPU1_MEMHOT_IN_LVC1_N")
	)
	(segment
		(start 101.928676 -230.35768)
		(end 101.772212 -230.086662)
		(width 0.0889)
		(layer "B.Cu")
		(net "H_CPU1_MEMHOT_IN_LVC1_N")
	)
	(segment
		(start 87.546688 -230.495856)
		(end 87.707216 -230.335328)
		(width 0.0889)
		(layer "B.Cu")
		(net "H_CPU1_MEMHOT_IN_LVC1_N")
	)
	(segment
		(start 74.270108 -203.75372)
		(end 74.270108 -224.29216)
		(width 0.12954)
		(layer "B.Cu")
		(net "H_CPU1_MEMHOT_IN_LVC1_N")
	)
	(segment
		(start 77.800962 -195.14566)
		(end 76.328778 -196.617844)
		(width 0.12954)
		(layer "B.Cu")
		(net "H_CPU1_MEMHOT_IN_LVC1_N")
	)
	(segment
		(start 79.727044 -229.749096)
		(end 80.789018 -230.81107)
		(width 0.12954)
		(layer "B.Cu")
		(net "H_CPU1_MEMHOT_IN_LVC1_N")
	)
	(segment
		(start 101.570282 -230.402384)
		(end 101.585014 -230.41102)
		(width 0.0889)
		(layer "B.Cu")
		(net "H_CPU1_MEMHOT_IN_LVC1_N")
	)
	(segment
		(start 81.424526 -175.20031)
		(end 81.424526 -177.326798)
		(width 0.12954)
		(layer "B.Cu")
		(net "H_CPU1_MEMHOT_IN_LVC1_N")
	)
	(segment
		(start 81.424526 -177.326798)
		(end 78.149958 -180.601366)
		(width 0.12954)
		(layer "B.Cu")
		(net "H_CPU1_MEMHOT_IN_LVC1_N")
	)
	(segment
		(start 90.682064 -230.41102)
		(end 90.692478 -230.404924)
		(width 0.0889)
		(layer "B.Cu")
		(net "H_CPU1_MEMHOT_IN_LVC1_N")
	)
	(segment
		(start 78.149958 -180.601366)
		(end 78.149958 -182.61457)
		(width 0.12954)
		(layer "B.Cu")
		(net "H_CPU1_MEMHOT_IN_LVC1_N")
	)
	(segment
		(start 94.051882 -230.402384)
		(end 94.066614 -230.41102)
		(width 0.0889)
		(layer "B.Cu")
		(net "H_CPU1_MEMHOT_IN_LVC1_N")
	)
	(segment
		(start 108.781596 -147.84324)
		(end 81.424526 -175.20031)
		(width 0.12954)
		(layer "B.Cu")
		(net "H_CPU1_MEMHOT_IN_LVC1_N")
	)
	(segment
		(start 83.822032 -230.495856)
		(end 87.546688 -230.495856)
		(width 0.0889)
		(layer "B.Cu")
		(net "H_CPU1_MEMHOT_IN_LVC1_N")
	)
	(segment
		(start 139.67968 -144.897348)
		(end 136.733788 -147.84324)
		(width 0.12954)
		(layer "B.Cu")
		(net "H_CPU1_MEMHOT_IN_LVC1_N")
	)
	(segment
		(start 80.789018 -230.81107)
		(end 83.506818 -230.81107)
		(width 0.12954)
		(layer "B.Cu")
		(net "H_CPU1_MEMHOT_IN_LVC1_N")
	)
	(segment
		(start 99.690682 -230.402384)
		(end 99.705414 -230.41102)
		(width 0.0889)
		(layer "B.Cu")
		(net "H_CPU1_MEMHOT_IN_LVC1_N")
	)
	(segment
		(start 95.931482 -230.402384)
		(end 95.946214 -230.41102)
		(width 0.0889)
		(layer "B.Cu")
		(net "H_CPU1_MEMHOT_IN_LVC1_N")
	)
	(segment
		(start 76.328778 -201.69505)
		(end 74.270108 -203.75372)
		(width 0.12954)
		(layer "B.Cu")
		(net "H_CPU1_MEMHOT_IN_LVC1_N")
	)
	(segment
		(start 141.43228 -144.897348)
		(end 139.67968 -144.897348)
		(width 0.12954)
		(layer "B.Cu")
		(net "H_CPU1_MEMHOT_IN_LVC1_N")
	)
	(segment
		(start 76.656438 -184.77865)
		(end 76.656438 -186.860434)
		(width 0.12954)
		(layer "B.Cu")
		(net "H_CPU1_MEMHOT_IN_LVC1_N")
	)
	(segment
		(start 78.149958 -182.61457)
		(end 77.310488 -183.45404)
		(width 0.12954)
		(layer "B.Cu")
		(net "H_CPU1_MEMHOT_IN_LVC1_N")
	)
	(segment
		(start 92.172282 -230.402384)
		(end 92.187014 -230.41102)
		(width 0.0889)
		(layer "B.Cu")
		(net "H_CPU1_MEMHOT_IN_LVC1_N")
	)
	(segment
		(start 89.352882 -230.402384)
		(end 89.367614 -230.41102)
		(width 0.0889)
		(layer "B.Cu")
		(net "H_CPU1_MEMHOT_IN_LVC1_N")
	)
	(segment
		(start 74.270108 -224.29216)
		(end 79.727044 -229.749096)
		(width 0.12954)
		(layer "B.Cu")
		(net "H_CPU1_MEMHOT_IN_LVC1_N")
	)
	(segment
		(start 83.506818 -230.81107)
		(end 83.822032 -230.495856)
		(width 0.12954)
		(layer "B.Cu")
		(net "H_CPU1_MEMHOT_IN_LVC1_N")
	)
	(segment
		(start 93.112082 -230.402384)
		(end 93.126814 -230.41102)
		(width 0.0889)
		(layer "B.Cu")
		(net "H_CPU1_MEMHOT_IN_LVC1_N")
	)
	(segment
		(start 77.310488 -183.45404)
		(end 77.310488 -184.1246)
		(width 0.12954)
		(layer "B.Cu")
		(net "H_CPU1_MEMHOT_IN_LVC1_N")
	)
	(segment
		(start 98.750882 -230.402384)
		(end 98.765614 -230.41102)
		(width 0.0889)
		(layer "B.Cu")
		(net "H_CPU1_MEMHOT_IN_LVC1_N")
	)
	(segment
		(start 76.328778 -196.617844)
		(end 76.328778 -201.69505)
		(width 0.12954)
		(layer "B.Cu")
		(net "H_CPU1_MEMHOT_IN_LVC1_N")
	)
	(segment
		(start 100.630482 -230.402384)
		(end 100.645214 -230.41102)
		(width 0.0889)
		(layer "B.Cu")
		(net "H_CPU1_MEMHOT_IN_LVC1_N")
	)
	(segment
		(start 136.733788 -147.84324)
		(end 108.781596 -147.84324)
		(width 0.12954)
		(layer "B.Cu")
		(net "H_CPU1_MEMHOT_IN_LVC1_N")
	)
	(segment
		(start 96.875854 -230.404924)
		(end 96.886268 -230.41102)
		(width 0.0889)
		(layer "B.Cu")
		(net "H_CPU1_MEMHOT_IN_LVC1_N")
	)
	(segment
		(start 87.707216 -230.335328)
		(end 88.14562 -230.335328)
		(width 0.0889)
		(layer "B.Cu")
		(net "H_CPU1_MEMHOT_IN_LVC1_N")
	)
	(segment
		(start 97.260664 -230.41102)
		(end 97.271078 -230.404924)
		(width 0.0889)
		(layer "B.Cu")
		(net "H_CPU1_MEMHOT_IN_LVC1_N")
	)
	(arc
		(start 94.066614 -230.41102)
		(mid 94.253812 -230.461163)
		(end 94.44101 -230.41102)
		(width 0.0889)
		(layer "B.Cu")
		(net "H_CPU1_MEMHOT_IN_LVC1_N")
	)
	(arc
		(start 88.80221 -230.41102)
		(mid 89.076409 -230.335185)
		(end 89.352882 -230.402384)
		(width 0.0889)
		(layer "B.Cu")
		(net "H_CPU1_MEMHOT_IN_LVC1_N")
	)
	(arc
		(start 101.01961 -230.41102)
		(mid 101.293809 -230.335185)
		(end 101.570282 -230.402384)
		(width 0.0889)
		(layer "B.Cu")
		(net "H_CPU1_MEMHOT_IN_LVC1_N")
	)
	(arc
		(start 97.825814 -230.41102)
		(mid 98.013012 -230.461163)
		(end 98.20021 -230.41102)
		(width 0.0889)
		(layer "B.Cu")
		(net "H_CPU1_MEMHOT_IN_LVC1_N")
	)
	(arc
		(start 91.62161 -230.41102)
		(mid 91.895809 -230.335185)
		(end 92.172282 -230.402384)
		(width 0.0889)
		(layer "B.Cu")
		(net "H_CPU1_MEMHOT_IN_LVC1_N")
	)
	(arc
		(start 91.247214 -230.41102)
		(mid 91.434412 -230.461163)
		(end 91.62161 -230.41102)
		(width 0.0889)
		(layer "B.Cu")
		(net "H_CPU1_MEMHOT_IN_LVC1_N")
	)
	(arc
		(start 95.38081 -230.41102)
		(mid 95.655009 -230.335185)
		(end 95.931482 -230.402384)
		(width 0.0889)
		(layer "B.Cu")
		(net "H_CPU1_MEMHOT_IN_LVC1_N")
	)
	(arc
		(start 92.187014 -230.41102)
		(mid 92.374212 -230.461163)
		(end 92.56141 -230.41102)
		(width 0.0889)
		(layer "B.Cu")
		(net "H_CPU1_MEMHOT_IN_LVC1_N")
	)
	(arc
		(start 90.692478 -230.404924)
		(mid 90.970656 -230.335201)
		(end 91.247214 -230.41102)
		(width 0.0889)
		(layer "B.Cu")
		(net "H_CPU1_MEMHOT_IN_LVC1_N")
	)
	(arc
		(start 101.585014 -230.41102)
		(mid 101.743502 -230.459953)
		(end 101.907594 -230.435658)
		(width 0.0889)
		(layer "B.Cu")
		(net "H_CPU1_MEMHOT_IN_LVC1_N")
	)
	(arc
		(start 100.645214 -230.41102)
		(mid 100.832412 -230.461163)
		(end 101.01961 -230.41102)
		(width 0.0889)
		(layer "B.Cu")
		(net "H_CPU1_MEMHOT_IN_LVC1_N")
	)
	(arc
		(start 93.126814 -230.41102)
		(mid 93.314012 -230.461163)
		(end 93.50121 -230.41102)
		(width 0.0889)
		(layer "B.Cu")
		(net "H_CPU1_MEMHOT_IN_LVC1_N")
	)
	(arc
		(start 89.367614 -230.41102)
		(mid 89.554812 -230.461163)
		(end 89.74201 -230.41102)
		(width 0.0889)
		(layer "B.Cu")
		(net "H_CPU1_MEMHOT_IN_LVC1_N")
	)
	(arc
		(start 98.765614 -230.41102)
		(mid 98.952812 -230.461163)
		(end 99.14001 -230.41102)
		(width 0.0889)
		(layer "B.Cu")
		(net "H_CPU1_MEMHOT_IN_LVC1_N")
	)
	(arc
		(start 99.14001 -230.41102)
		(mid 99.414209 -230.335185)
		(end 99.690682 -230.402384)
		(width 0.0889)
		(layer "B.Cu")
		(net "H_CPU1_MEMHOT_IN_LVC1_N")
	)
	(arc
		(start 90.307668 -230.41102)
		(mid 90.494866 -230.461163)
		(end 90.682064 -230.41102)
		(width 0.0889)
		(layer "B.Cu")
		(net "H_CPU1_MEMHOT_IN_LVC1_N")
	)
	(arc
		(start 89.74201 -230.41102)
		(mid 90.018823 -230.33515)
		(end 90.297254 -230.404924)
		(width 0.0889)
		(layer "B.Cu")
		(net "H_CPU1_MEMHOT_IN_LVC1_N")
	)
	(arc
		(start 98.20021 -230.41102)
		(mid 98.474409 -230.335185)
		(end 98.750882 -230.402384)
		(width 0.0889)
		(layer "B.Cu")
		(net "H_CPU1_MEMHOT_IN_LVC1_N")
	)
	(arc
		(start 95.946214 -230.41102)
		(mid 96.133412 -230.461163)
		(end 96.32061 -230.41102)
		(width 0.0889)
		(layer "B.Cu")
		(net "H_CPU1_MEMHOT_IN_LVC1_N")
	)
	(arc
		(start 95.006414 -230.41102)
		(mid 95.193612 -230.461163)
		(end 95.38081 -230.41102)
		(width 0.0889)
		(layer "B.Cu")
		(net "H_CPU1_MEMHOT_IN_LVC1_N")
	)
	(arc
		(start 100.07981 -230.41102)
		(mid 100.354009 -230.335185)
		(end 100.630482 -230.402384)
		(width 0.0889)
		(layer "B.Cu")
		(net "H_CPU1_MEMHOT_IN_LVC1_N")
	)
	(arc
		(start 99.705414 -230.41102)
		(mid 99.892612 -230.461163)
		(end 100.07981 -230.41102)
		(width 0.0889)
		(layer "B.Cu")
		(net "H_CPU1_MEMHOT_IN_LVC1_N")
	)
	(arc
		(start 88.181942 -230.336344)
		(mid 88.30917 -230.359542)
		(end 88.427814 -230.41102)
		(width 0.0889)
		(layer "B.Cu")
		(net "H_CPU1_MEMHOT_IN_LVC1_N")
	)
	(arc
		(start 96.32061 -230.41102)
		(mid 96.597423 -230.33515)
		(end 96.875854 -230.404924)
		(width 0.0889)
		(layer "B.Cu")
		(net "H_CPU1_MEMHOT_IN_LVC1_N")
	)
	(arc
		(start 97.271078 -230.404924)
		(mid 97.549256 -230.335201)
		(end 97.825814 -230.41102)
		(width 0.0889)
		(layer "B.Cu")
		(net "H_CPU1_MEMHOT_IN_LVC1_N")
	)
	(arc
		(start 88.14562 -230.335328)
		(mid 88.163789 -230.335547)
		(end 88.181942 -230.336344)
		(width 0.0889)
		(layer "B.Cu")
		(net "H_CPU1_MEMHOT_IN_LVC1_N")
	)
	(arc
		(start 93.50121 -230.41102)
		(mid 93.775409 -230.335185)
		(end 94.051882 -230.402384)
		(width 0.0889)
		(layer "B.Cu")
		(net "H_CPU1_MEMHOT_IN_LVC1_N")
	)
	(arc
		(start 92.56141 -230.41102)
		(mid 92.835609 -230.335185)
		(end 93.112082 -230.402384)
		(width 0.0889)
		(layer "B.Cu")
		(net "H_CPU1_MEMHOT_IN_LVC1_N")
	)
	(arc
		(start 88.427814 -230.41102)
		(mid 88.615012 -230.461163)
		(end 88.80221 -230.41102)
		(width 0.0889)
		(layer "B.Cu")
		(net "H_CPU1_MEMHOT_IN_LVC1_N")
	)
	(arc
		(start 96.886268 -230.41102)
		(mid 97.073466 -230.461163)
		(end 97.260664 -230.41102)
		(width 0.0889)
		(layer "B.Cu")
		(net "H_CPU1_MEMHOT_IN_LVC1_N")
	)
	(arc
		(start 94.44101 -230.41102)
		(mid 94.715209 -230.335185)
		(end 94.991682 -230.402384)
		(width 0.0889)
		(layer "B.Cu")
		(net "H_CPU1_MEMHOT_IN_LVC1_N")
	)
	(segment
		(start 145.27022 -106.992928)
		(end 144.6784 -106.992928)
		(width 0.127)
		(layer "In2.Cu")
		(net "H_CPU1_MEMHOT_IN_LVC1_N")
	)
	(segment
		(start 144.6784 -106.992928)
		(end 140.97508 -110.696248)
		(width 0.127)
		(layer "In2.Cu")
		(net "H_CPU1_MEMHOT_IN_LVC1_N")
	)
	(segment
		(start 140.97508 -144.440148)
		(end 141.43228 -144.897348)
		(width 0.127)
		(layer "In2.Cu")
		(net "H_CPU1_MEMHOT_IN_LVC1_N")
	)
	(segment
		(start 140.97508 -110.696248)
		(end 140.97508 -144.440148)
		(width 0.127)
		(layer "In2.Cu")
		(net "H_CPU1_MEMHOT_IN_LVC1_N")
	)
	(segment
		(start 186.2455 -93.103954)
		(end 186.486546 -93.345)
		(width 0.127)
		(layer "In11.Cu")
		(net "H_CPU1_MEMHOT_IN_LVC1_N")
	)
	(segment
		(start 145.92808 -98.110548)
		(end 162.493452 -98.110548)
		(width 0.127)
		(layer "In11.Cu")
		(net "H_CPU1_MEMHOT_IN_LVC1_N")
	)
	(segment
		(start 183.896 -91.0336)
		(end 184.944766 -91.0336)
		(width 0.127)
		(layer "In11.Cu")
		(net "H_CPU1_MEMHOT_IN_LVC1_N")
	)
	(segment
		(start 196.430392 -97.955608)
		(end 198.869808 -97.955608)
		(width 0.127)
		(layer "In11.Cu")
		(net "H_CPU1_MEMHOT_IN_LVC1_N")
	)
	(segment
		(start 182.052722 -89.190322)
		(end 183.896 -91.0336)
		(width 0.127)
		(layer "In11.Cu")
		(net "H_CPU1_MEMHOT_IN_LVC1_N")
	)
	(segment
		(start 198.869808 -97.955608)
		(end 200.853548 -99.939348)
		(width 0.127)
		(layer "In11.Cu")
		(net "H_CPU1_MEMHOT_IN_LVC1_N")
	)
	(segment
		(start 200.853548 -99.939348)
		(end 202.06208 -99.939348)
		(width 0.127)
		(layer "In11.Cu")
		(net "H_CPU1_MEMHOT_IN_LVC1_N")
	)
	(segment
		(start 184.944766 -91.0336)
		(end 186.2455 -92.334334)
		(width 0.127)
		(layer "In11.Cu")
		(net "H_CPU1_MEMHOT_IN_LVC1_N")
	)
	(segment
		(start 145.27022 -106.992928)
		(end 145.27022 -98.768408)
		(width 0.127)
		(layer "In11.Cu")
		(net "H_CPU1_MEMHOT_IN_LVC1_N")
	)
	(segment
		(start 189.827408 -94.120208)
		(end 192.594992 -94.120208)
		(width 0.127)
		(layer "In11.Cu")
		(net "H_CPU1_MEMHOT_IN_LVC1_N")
	)
	(segment
		(start 189.0522 -93.345)
		(end 189.827408 -94.120208)
		(width 0.127)
		(layer "In11.Cu")
		(net "H_CPU1_MEMHOT_IN_LVC1_N")
	)
	(segment
		(start 162.493452 -98.110548)
		(end 171.413678 -89.190322)
		(width 0.127)
		(layer "In11.Cu")
		(net "H_CPU1_MEMHOT_IN_LVC1_N")
	)
	(segment
		(start 171.413678 -89.190322)
		(end 182.052722 -89.190322)
		(width 0.127)
		(layer "In11.Cu")
		(net "H_CPU1_MEMHOT_IN_LVC1_N")
	)
	(segment
		(start 192.594992 -94.120208)
		(end 196.430392 -97.955608)
		(width 0.127)
		(layer "In11.Cu")
		(net "H_CPU1_MEMHOT_IN_LVC1_N")
	)
	(segment
		(start 145.27022 -98.768408)
		(end 145.92808 -98.110548)
		(width 0.127)
		(layer "In11.Cu")
		(net "H_CPU1_MEMHOT_IN_LVC1_N")
	)
	(segment
		(start 186.2455 -92.334334)
		(end 186.2455 -93.103954)
		(width 0.127)
		(layer "In11.Cu")
		(net "H_CPU1_MEMHOT_IN_LVC1_N")
	)
	(segment
		(start 186.486546 -93.345)
		(end 189.0522 -93.345)
		(width 0.127)
		(layer "In11.Cu")
		(net "H_CPU1_MEMHOT_IN_LVC1_N")
	)
	(segment
		(start 105.061512 -230.900732)
		(end 105.061766 -230.900478)
		(width 0.12954)
		(layer "F.Cu")
		(net "H_CPU1_ERR2_LVC1_R_N")
	)
	(segment
		(start 105.061512 -231.436418)
		(end 105.061512 -230.900732)
		(width 0.12954)
		(layer "F.Cu")
		(net "H_CPU1_ERR2_LVC1_R_N")
	)
	(via
		(at 79.099918 -198.72325)
		(size 0.6604)
		(drill 0.3302)
		(layers "F.Cu" "B.Cu")
		(net "H_CPU1_ERR2_LVC1_R_N")
	)
	(via
		(at 105.061766 -230.900478)
		(size 0.4572)
		(drill 0.2032)
		(layers "F.Cu" "B.Cu")
		(net "H_CPU1_ERR2_LVC1_R_N")
	)
	(segment
		(start 91.247468 -228.783388)
		(end 91.237054 -228.777292)
		(width 0.0889)
		(layer "B.Cu")
		(net "H_CPU1_ERR2_LVC1_R_N")
	)
	(segment
		(start 105.21823 -231.171496)
		(end 105.197148 -231.249474)
		(width 0.0889)
		(layer "B.Cu")
		(net "H_CPU1_ERR2_LVC1_R_N")
	)
	(segment
		(start 98.765614 -228.783388)
		(end 98.7552 -228.777292)
		(width 0.0889)
		(layer "B.Cu")
		(net "H_CPU1_ERR2_LVC1_R_N")
	)
	(segment
		(start 105.061766 -230.900478)
		(end 105.21823 -231.171496)
		(width 0.0889)
		(layer "B.Cu")
		(net "H_CPU1_ERR2_LVC1_R_N")
	)
	(segment
		(start 94.066614 -228.783388)
		(end 94.051882 -228.774752)
		(width 0.0889)
		(layer "B.Cu")
		(net "H_CPU1_ERR2_LVC1_R_N")
	)
	(segment
		(start 103.464614 -230.41102)
		(end 103.455724 -230.40594)
		(width 0.0889)
		(layer "B.Cu")
		(net "H_CPU1_ERR2_LVC1_R_N")
	)
	(segment
		(start 88.427814 -228.783388)
		(end 88.4174 -228.777292)
		(width 0.0889)
		(layer "B.Cu")
		(net "H_CPU1_ERR2_LVC1_R_N")
	)
	(segment
		(start 103.934768 -231.224836)
		(end 103.925878 -231.219756)
		(width 0.0889)
		(layer "B.Cu")
		(net "H_CPU1_ERR2_LVC1_R_N")
	)
	(segment
		(start 103.277162 -230.086662)
		(end 103.277162 -230.071168)
		(width 0.0889)
		(layer "B.Cu")
		(net "H_CPU1_ERR2_LVC1_R_N")
	)
	(segment
		(start 92.187014 -228.783388)
		(end 92.1766 -228.777292)
		(width 0.0889)
		(layer "B.Cu")
		(net "H_CPU1_ERR2_LVC1_R_N")
	)
	(segment
		(start 79.541878 -189.130178)
		(end 78.983078 -187.78093)
		(width 0.12954)
		(layer "B.Cu")
		(net "H_CPU1_ERR2_LVC1_R_N")
	)
	(segment
		(start 79.099918 -198.72325)
		(end 79.099918 -196.37121)
		(width 0.12954)
		(layer "B.Cu")
		(net "H_CPU1_ERR2_LVC1_R_N")
	)
	(segment
		(start 102.53091 -228.786944)
		(end 102.524814 -228.783388)
		(width 0.0889)
		(layer "B.Cu")
		(net "H_CPU1_ERR2_LVC1_R_N")
	)
	(segment
		(start 79.414624 -184.934098)
		(end 79.414624 -184.496202)
		(width 0.12954)
		(layer "B.Cu")
		(net "H_CPU1_ERR2_LVC1_R_N")
	)
	(segment
		(start 82.097118 -228.528626)
		(end 76.617068 -223.048576)
		(width 0.12954)
		(layer "B.Cu")
		(net "H_CPU1_ERR2_LVC1_R_N")
	)
	(segment
		(start 93.126814 -228.783388)
		(end 93.112082 -228.774752)
		(width 0.0889)
		(layer "B.Cu")
		(net "H_CPU1_ERR2_LVC1_R_N")
	)
	(segment
		(start 83.894168 -228.528626)
		(end 82.097118 -228.528626)
		(width 0.12954)
		(layer "B.Cu")
		(net "H_CPU1_ERR2_LVC1_R_N")
	)
	(segment
		(start 86.737698 -228.528626)
		(end 83.894168 -228.528626)
		(width 0.0889)
		(layer "B.Cu")
		(net "H_CPU1_ERR2_LVC1_R_N")
	)
	(segment
		(start 89.367614 -228.783388)
		(end 89.352882 -228.774752)
		(width 0.0889)
		(layer "B.Cu")
		(net "H_CPU1_ERR2_LVC1_R_N")
	)
	(segment
		(start 97.826068 -228.783388)
		(end 97.815654 -228.777292)
		(width 0.0889)
		(layer "B.Cu")
		(net "H_CPU1_ERR2_LVC1_R_N")
	)
	(segment
		(start 95.946214 -228.783388)
		(end 95.931482 -228.774752)
		(width 0.0889)
		(layer "B.Cu")
		(net "H_CPU1_ERR2_LVC1_R_N")
	)
	(segment
		(start 99.705414 -228.783388)
		(end 99.690682 -228.774752)
		(width 0.0889)
		(layer "B.Cu")
		(net "H_CPU1_ERR2_LVC1_R_N")
	)
	(segment
		(start 79.099918 -196.37121)
		(end 79.541878 -195.92925)
		(width 0.12954)
		(layer "B.Cu")
		(net "H_CPU1_ERR2_LVC1_R_N")
	)
	(segment
		(start 78.983078 -185.365644)
		(end 79.414624 -184.934098)
		(width 0.12954)
		(layer "B.Cu")
		(net "H_CPU1_ERR2_LVC1_R_N")
	)
	(segment
		(start 100.645214 -228.783388)
		(end 100.630482 -228.774752)
		(width 0.0889)
		(layer "B.Cu")
		(net "H_CPU1_ERR2_LVC1_R_N")
	)
	(segment
		(start 79.541878 -195.92925)
		(end 79.541878 -189.130178)
		(width 0.12954)
		(layer "B.Cu")
		(net "H_CPU1_ERR2_LVC1_R_N")
	)
	(segment
		(start 103.47071 -230.414576)
		(end 103.464614 -230.41102)
		(width 0.0889)
		(layer "B.Cu")
		(net "H_CPU1_ERR2_LVC1_R_N")
	)
	(segment
		(start 76.617068 -223.048576)
		(end 76.617068 -205.549754)
		(width 0.12954)
		(layer "B.Cu")
		(net "H_CPU1_ERR2_LVC1_R_N")
	)
	(segment
		(start 102.994968 -229.597204)
		(end 102.986078 -229.592124)
		(width 0.0889)
		(layer "B.Cu")
		(net "H_CPU1_ERR2_LVC1_R_N")
	)
	(segment
		(start 79.099918 -203.066904)
		(end 79.099918 -198.72325)
		(width 0.12954)
		(layer "B.Cu")
		(net "H_CPU1_ERR2_LVC1_R_N")
	)
	(segment
		(start 102.524814 -228.783388)
		(end 102.510082 -228.774752)
		(width 0.0889)
		(layer "B.Cu")
		(net "H_CPU1_ERR2_LVC1_R_N")
	)
	(segment
		(start 87.042498 -228.833426)
		(end 86.737698 -228.528626)
		(width 0.0889)
		(layer "B.Cu")
		(net "H_CPU1_ERR2_LVC1_R_N")
	)
	(segment
		(start 87.675466 -228.833426)
		(end 87.042498 -228.833426)
		(width 0.0889)
		(layer "B.Cu")
		(net "H_CPU1_ERR2_LVC1_R_N")
	)
	(segment
		(start 104.323896 -231.2162)
		(end 104.309164 -231.224836)
		(width 0.0889)
		(layer "B.Cu")
		(net "H_CPU1_ERR2_LVC1_R_N")
	)
	(segment
		(start 78.983078 -187.78093)
		(end 78.983078 -185.365644)
		(width 0.12954)
		(layer "B.Cu")
		(net "H_CPU1_ERR2_LVC1_R_N")
	)
	(segment
		(start 96.886014 -228.783388)
		(end 96.871282 -228.774752)
		(width 0.0889)
		(layer "B.Cu")
		(net "H_CPU1_ERR2_LVC1_R_N")
	)
	(segment
		(start 76.617068 -205.549754)
		(end 79.099918 -203.066904)
		(width 0.12954)
		(layer "B.Cu")
		(net "H_CPU1_ERR2_LVC1_R_N")
	)
	(segment
		(start 90.307414 -228.783388)
		(end 90.292682 -228.774752)
		(width 0.0889)
		(layer "B.Cu")
		(net "H_CPU1_ERR2_LVC1_R_N")
	)
	(arc
		(start 93.50121 -228.783388)
		(mid 93.314012 -228.833531)
		(end 93.126814 -228.783388)
		(width 0.0889)
		(layer "B.Cu")
		(net "H_CPU1_ERR2_LVC1_R_N")
	)
	(arc
		(start 89.74201 -228.783388)
		(mid 89.554812 -228.833531)
		(end 89.367614 -228.783388)
		(width 0.0889)
		(layer "B.Cu")
		(net "H_CPU1_ERR2_LVC1_R_N")
	)
	(arc
		(start 95.38081 -228.783388)
		(mid 95.193612 -228.833531)
		(end 95.006414 -228.783388)
		(width 0.0889)
		(layer "B.Cu")
		(net "H_CPU1_ERR2_LVC1_R_N")
	)
	(arc
		(start 91.237054 -228.777292)
		(mid 90.958622 -228.707446)
		(end 90.68181 -228.783388)
		(width 0.0889)
		(layer "B.Cu")
		(net "H_CPU1_ERR2_LVC1_R_N")
	)
	(arc
		(start 102.986078 -229.592124)
		(mid 102.855164 -229.455764)
		(end 102.807516 -229.272846)
		(width 0.0889)
		(layer "B.Cu")
		(net "H_CPU1_ERR2_LVC1_R_N")
	)
	(arc
		(start 91.621864 -228.783388)
		(mid 91.434666 -228.833531)
		(end 91.247468 -228.783388)
		(width 0.0889)
		(layer "B.Cu")
		(net "H_CPU1_ERR2_LVC1_R_N")
	)
	(arc
		(start 101.01961 -228.783388)
		(mid 100.832412 -228.833531)
		(end 100.645214 -228.783388)
		(width 0.0889)
		(layer "B.Cu")
		(net "H_CPU1_ERR2_LVC1_R_N")
	)
	(arc
		(start 98.200464 -228.783388)
		(mid 98.013266 -228.833531)
		(end 97.826068 -228.783388)
		(width 0.0889)
		(layer "B.Cu")
		(net "H_CPU1_ERR2_LVC1_R_N")
	)
	(arc
		(start 103.747316 -230.900478)
		(mid 103.673325 -230.620912)
		(end 103.47071 -230.414576)
		(width 0.0889)
		(layer "B.Cu")
		(net "H_CPU1_ERR2_LVC1_R_N")
	)
	(arc
		(start 94.051882 -228.774752)
		(mid 93.775407 -228.707432)
		(end 93.50121 -228.783388)
		(width 0.0889)
		(layer "B.Cu")
		(net "H_CPU1_ERR2_LVC1_R_N")
	)
	(arc
		(start 93.112082 -228.774752)
		(mid 92.835607 -228.707432)
		(end 92.56141 -228.783388)
		(width 0.0889)
		(layer "B.Cu")
		(net "H_CPU1_ERR2_LVC1_R_N")
	)
	(arc
		(start 99.690682 -228.774752)
		(mid 99.414207 -228.707432)
		(end 99.14001 -228.783388)
		(width 0.0889)
		(layer "B.Cu")
		(net "H_CPU1_ERR2_LVC1_R_N")
	)
	(arc
		(start 88.4174 -228.777292)
		(mid 88.139222 -228.707569)
		(end 87.862664 -228.783388)
		(width 0.0889)
		(layer "B.Cu")
		(net "H_CPU1_ERR2_LVC1_R_N")
	)
	(arc
		(start 94.44101 -228.783388)
		(mid 94.253812 -228.833531)
		(end 94.066614 -228.783388)
		(width 0.0889)
		(layer "B.Cu")
		(net "H_CPU1_ERR2_LVC1_R_N")
	)
	(arc
		(start 92.56141 -228.783388)
		(mid 92.374212 -228.833531)
		(end 92.187014 -228.783388)
		(width 0.0889)
		(layer "B.Cu")
		(net "H_CPU1_ERR2_LVC1_R_N")
	)
	(arc
		(start 90.68181 -228.783388)
		(mid 90.494612 -228.833531)
		(end 90.307414 -228.783388)
		(width 0.0889)
		(layer "B.Cu")
		(net "H_CPU1_ERR2_LVC1_R_N")
	)
	(arc
		(start 89.352882 -228.774752)
		(mid 89.076407 -228.707432)
		(end 88.80221 -228.783388)
		(width 0.0889)
		(layer "B.Cu")
		(net "H_CPU1_ERR2_LVC1_R_N")
	)
	(arc
		(start 103.277162 -230.071168)
		(mid 103.197792 -229.797434)
		(end 102.994968 -229.597204)
		(width 0.0889)
		(layer "B.Cu")
		(net "H_CPU1_ERR2_LVC1_R_N")
	)
	(arc
		(start 104.874568 -231.224836)
		(mid 104.600339 -231.148911)
		(end 104.323896 -231.2162)
		(width 0.0889)
		(layer "B.Cu")
		(net "H_CPU1_ERR2_LVC1_R_N")
	)
	(arc
		(start 97.815654 -228.777292)
		(mid 97.537222 -228.707446)
		(end 97.26041 -228.783388)
		(width 0.0889)
		(layer "B.Cu")
		(net "H_CPU1_ERR2_LVC1_R_N")
	)
	(arc
		(start 96.32061 -228.783388)
		(mid 96.133412 -228.833531)
		(end 95.946214 -228.783388)
		(width 0.0889)
		(layer "B.Cu")
		(net "H_CPU1_ERR2_LVC1_R_N")
	)
	(arc
		(start 100.07981 -228.783388)
		(mid 99.892612 -228.833531)
		(end 99.705414 -228.783388)
		(width 0.0889)
		(layer "B.Cu")
		(net "H_CPU1_ERR2_LVC1_R_N")
	)
	(arc
		(start 96.871282 -228.774752)
		(mid 96.594807 -228.707432)
		(end 96.32061 -228.783388)
		(width 0.0889)
		(layer "B.Cu")
		(net "H_CPU1_ERR2_LVC1_R_N")
	)
	(arc
		(start 101.95941 -228.783388)
		(mid 101.772212 -228.833531)
		(end 101.585014 -228.783388)
		(width 0.0889)
		(layer "B.Cu")
		(net "H_CPU1_ERR2_LVC1_R_N")
	)
	(arc
		(start 98.7552 -228.777292)
		(mid 98.477022 -228.707569)
		(end 98.200464 -228.783388)
		(width 0.0889)
		(layer "B.Cu")
		(net "H_CPU1_ERR2_LVC1_R_N")
	)
	(arc
		(start 99.14001 -228.783388)
		(mid 98.952812 -228.833531)
		(end 98.765614 -228.783388)
		(width 0.0889)
		(layer "B.Cu")
		(net "H_CPU1_ERR2_LVC1_R_N")
	)
	(arc
		(start 104.309164 -231.224836)
		(mid 104.121966 -231.274979)
		(end 103.934768 -231.224836)
		(width 0.0889)
		(layer "B.Cu")
		(net "H_CPU1_ERR2_LVC1_R_N")
	)
	(arc
		(start 95.006414 -228.783388)
		(mid 94.723712 -228.707612)
		(end 94.44101 -228.783388)
		(width 0.0889)
		(layer "B.Cu")
		(net "H_CPU1_ERR2_LVC1_R_N")
	)
	(arc
		(start 105.197148 -231.249474)
		(mid 105.033052 -231.273821)
		(end 104.874568 -231.224836)
		(width 0.0889)
		(layer "B.Cu")
		(net "H_CPU1_ERR2_LVC1_R_N")
	)
	(arc
		(start 100.630482 -228.774752)
		(mid 100.354007 -228.707432)
		(end 100.07981 -228.783388)
		(width 0.0889)
		(layer "B.Cu")
		(net "H_CPU1_ERR2_LVC1_R_N")
	)
	(arc
		(start 102.510082 -228.774752)
		(mid 102.233607 -228.707432)
		(end 101.95941 -228.783388)
		(width 0.0889)
		(layer "B.Cu")
		(net "H_CPU1_ERR2_LVC1_R_N")
	)
	(arc
		(start 92.1766 -228.777292)
		(mid 91.898422 -228.707569)
		(end 91.621864 -228.783388)
		(width 0.0889)
		(layer "B.Cu")
		(net "H_CPU1_ERR2_LVC1_R_N")
	)
	(arc
		(start 103.455724 -230.40594)
		(mid 103.32481 -230.26958)
		(end 103.277162 -230.086662)
		(width 0.0889)
		(layer "B.Cu")
		(net "H_CPU1_ERR2_LVC1_R_N")
	)
	(arc
		(start 87.862664 -228.783388)
		(mid 87.772357 -228.820717)
		(end 87.675466 -228.833426)
		(width 0.0889)
		(layer "B.Cu")
		(net "H_CPU1_ERR2_LVC1_R_N")
	)
	(arc
		(start 97.26041 -228.783388)
		(mid 97.073212 -228.833531)
		(end 96.886014 -228.783388)
		(width 0.0889)
		(layer "B.Cu")
		(net "H_CPU1_ERR2_LVC1_R_N")
	)
	(arc
		(start 95.931482 -228.774752)
		(mid 95.655007 -228.707432)
		(end 95.38081 -228.783388)
		(width 0.0889)
		(layer "B.Cu")
		(net "H_CPU1_ERR2_LVC1_R_N")
	)
	(arc
		(start 90.292682 -228.774752)
		(mid 90.016207 -228.707432)
		(end 89.74201 -228.783388)
		(width 0.0889)
		(layer "B.Cu")
		(net "H_CPU1_ERR2_LVC1_R_N")
	)
	(arc
		(start 102.807516 -229.272846)
		(mid 102.733525 -228.99328)
		(end 102.53091 -228.786944)
		(width 0.0889)
		(layer "B.Cu")
		(net "H_CPU1_ERR2_LVC1_R_N")
	)
	(arc
		(start 88.80221 -228.783388)
		(mid 88.615012 -228.833531)
		(end 88.427814 -228.783388)
		(width 0.0889)
		(layer "B.Cu")
		(net "H_CPU1_ERR2_LVC1_R_N")
	)
	(arc
		(start 101.585014 -228.783388)
		(mid 101.302312 -228.707612)
		(end 101.01961 -228.783388)
		(width 0.0889)
		(layer "B.Cu")
		(net "H_CPU1_ERR2_LVC1_R_N")
	)
	(arc
		(start 103.925878 -231.219756)
		(mid 103.794964 -231.083396)
		(end 103.747316 -230.900478)
		(width 0.0889)
		(layer "B.Cu")
		(net "H_CPU1_ERR2_LVC1_R_N")
	)
	(segment
		(start 103.182166 -231.436164)
		(end 103.182166 -230.900478)
		(width 0.12954)
		(layer "F.Cu")
		(net "H_CPU1_ERR1_LVC1_R_N")
	)
	(segment
		(start 103.181912 -231.436418)
		(end 103.182166 -231.436164)
		(width 0.12954)
		(layer "F.Cu")
		(net "H_CPU1_ERR1_LVC1_R_N")
	)
	(via
		(at 77.14742 -225.350832)
		(size 0.6604)
		(drill 0.3302)
		(layers "F.Cu" "B.Cu")
		(net "H_CPU1_ERR1_LVC1_R_N")
	)
	(via
		(at 103.182166 -230.900478)
		(size 0.4572)
		(drill 0.2032)
		(layers "F.Cu" "B.Cu")
		(net "H_CPU1_ERR1_LVC1_R_N")
	)
	(segment
		(start 102.337362 -230.086662)
		(end 102.337362 -230.071168)
		(width 0.0889)
		(layer "B.Cu")
		(net "H_CPU1_ERR1_LVC1_R_N")
	)
	(segment
		(start 85.983318 -229.392226)
		(end 85.692488 -229.683056)
		(width 0.0889)
		(layer "B.Cu")
		(net "H_CPU1_ERR1_LVC1_R_N")
	)
	(segment
		(start 89.287096 -229.588568)
		(end 89.272364 -229.597204)
		(width 0.0889)
		(layer "B.Cu")
		(net "H_CPU1_ERR1_LVC1_R_N")
	)
	(segment
		(start 97.745296 -229.588568)
		(end 97.730564 -229.597204)
		(width 0.0889)
		(layer "B.Cu")
		(net "H_CPU1_ERR1_LVC1_R_N")
	)
	(segment
		(start 83.768692 -229.58679)
		(end 81.383378 -229.58679)
		(width 0.12954)
		(layer "B.Cu")
		(net "H_CPU1_ERR1_LVC1_R_N")
	)
	(segment
		(start 77.707998 -196.97827)
		(end 78.974442 -195.711826)
		(width 0.12954)
		(layer "B.Cu")
		(net "H_CPU1_ERR1_LVC1_R_N")
	)
	(segment
		(start 77.707998 -202.20813)
		(end 77.707998 -196.97827)
		(width 0.12954)
		(layer "B.Cu")
		(net "H_CPU1_ERR1_LVC1_R_N")
	)
	(segment
		(start 78.223618 -185.28411)
		(end 78.223618 -184.510426)
		(width 0.12954)
		(layer "B.Cu")
		(net "H_CPU1_ERR1_LVC1_R_N")
	)
	(segment
		(start 88.347296 -229.588568)
		(end 88.332564 -229.597204)
		(width 0.0889)
		(layer "B.Cu")
		(net "H_CPU1_ERR1_LVC1_R_N")
	)
	(segment
		(start 88.145366 -229.64775)
		(end 87.91575 -229.64775)
		(width 0.0889)
		(layer "B.Cu")
		(net "H_CPU1_ERR1_LVC1_R_N")
	)
	(segment
		(start 87.91575 -229.64775)
		(end 87.660226 -229.392226)
		(width 0.0889)
		(layer "B.Cu")
		(net "H_CPU1_ERR1_LVC1_R_N")
	)
	(segment
		(start 102.524814 -230.41102)
		(end 102.515924 -230.40594)
		(width 0.0889)
		(layer "B.Cu")
		(net "H_CPU1_ERR1_LVC1_R_N")
	)
	(segment
		(start 92.106496 -229.588568)
		(end 92.091764 -229.597204)
		(width 0.0889)
		(layer "B.Cu")
		(net "H_CPU1_ERR1_LVC1_R_N")
	)
	(segment
		(start 78.974442 -195.711826)
		(end 78.974442 -189.249304)
		(width 0.12954)
		(layer "B.Cu")
		(net "H_CPU1_ERR1_LVC1_R_N")
	)
	(segment
		(start 102.53091 -230.414576)
		(end 102.524814 -230.41102)
		(width 0.0889)
		(layer "B.Cu")
		(net "H_CPU1_ERR1_LVC1_R_N")
	)
	(segment
		(start 91.166696 -229.588568)
		(end 91.151964 -229.597204)
		(width 0.0889)
		(layer "B.Cu")
		(net "H_CPU1_ERR1_LVC1_R_N")
	)
	(segment
		(start 100.560378 -229.591108)
		(end 100.549964 -229.597204)
		(width 0.0889)
		(layer "B.Cu")
		(net "H_CPU1_ERR1_LVC1_R_N")
	)
	(segment
		(start 85.692488 -229.683056)
		(end 83.864958 -229.683056)
		(width 0.0889)
		(layer "B.Cu")
		(net "H_CPU1_ERR1_LVC1_R_N")
	)
	(segment
		(start 98.678238 -229.592632)
		(end 98.670364 -229.597204)
		(width 0.0889)
		(layer "B.Cu")
		(net "H_CPU1_ERR1_LVC1_R_N")
	)
	(segment
		(start 94.921324 -229.591108)
		(end 94.91091 -229.597204)
		(width 0.0889)
		(layer "B.Cu")
		(net "H_CPU1_ERR1_LVC1_R_N")
	)
	(segment
		(start 75.443588 -204.47254)
		(end 77.707998 -202.20813)
		(width 0.12954)
		(layer "B.Cu")
		(net "H_CPU1_ERR1_LVC1_R_N")
	)
	(segment
		(start 75.443588 -223.647)
		(end 75.443588 -204.47254)
		(width 0.12954)
		(layer "B.Cu")
		(net "H_CPU1_ERR1_LVC1_R_N")
	)
	(segment
		(start 99.624896 -229.588568)
		(end 99.610164 -229.597204)
		(width 0.0889)
		(layer "B.Cu")
		(net "H_CPU1_ERR1_LVC1_R_N")
	)
	(segment
		(start 101.499924 -229.591108)
		(end 101.48951 -229.597204)
		(width 0.0889)
		(layer "B.Cu")
		(net "H_CPU1_ERR1_LVC1_R_N")
	)
	(segment
		(start 98.685096 -229.588568)
		(end 98.678238 -229.592632)
		(width 0.0889)
		(layer "B.Cu")
		(net "H_CPU1_ERR1_LVC1_R_N")
	)
	(segment
		(start 77.14742 -225.350832)
		(end 75.443588 -223.647)
		(width 0.12954)
		(layer "B.Cu")
		(net "H_CPU1_ERR1_LVC1_R_N")
	)
	(segment
		(start 78.091538 -187.117482)
		(end 78.091538 -185.41619)
		(width 0.12954)
		(layer "B.Cu")
		(net "H_CPU1_ERR1_LVC1_R_N")
	)
	(segment
		(start 103.182166 -230.900478)
		(end 103.210868 -230.950262)
		(width 0.0889)
		(layer "B.Cu")
		(net "H_CPU1_ERR1_LVC1_R_N")
	)
	(segment
		(start 93.981778 -229.591108)
		(end 93.971364 -229.597204)
		(width 0.0889)
		(layer "B.Cu")
		(net "H_CPU1_ERR1_LVC1_R_N")
	)
	(segment
		(start 103.210868 -230.950262)
		(end 103.33863 -231.171496)
		(width 0.0889)
		(layer "B.Cu")
		(net "H_CPU1_ERR1_LVC1_R_N")
	)
	(segment
		(start 78.974442 -189.249304)
		(end 78.091538 -187.117482)
		(width 0.12954)
		(layer "B.Cu")
		(net "H_CPU1_ERR1_LVC1_R_N")
	)
	(segment
		(start 87.660226 -229.392226)
		(end 85.983318 -229.392226)
		(width 0.0889)
		(layer "B.Cu")
		(net "H_CPU1_ERR1_LVC1_R_N")
	)
	(segment
		(start 93.046296 -229.588568)
		(end 93.031564 -229.597204)
		(width 0.0889)
		(layer "B.Cu")
		(net "H_CPU1_ERR1_LVC1_R_N")
	)
	(segment
		(start 103.33863 -231.171496)
		(end 103.317548 -231.249474)
		(width 0.0889)
		(layer "B.Cu")
		(net "H_CPU1_ERR1_LVC1_R_N")
	)
	(segment
		(start 78.091538 -185.41619)
		(end 78.223618 -185.28411)
		(width 0.12954)
		(layer "B.Cu")
		(net "H_CPU1_ERR1_LVC1_R_N")
	)
	(segment
		(start 95.865696 -229.588568)
		(end 95.850964 -229.597204)
		(width 0.0889)
		(layer "B.Cu")
		(net "H_CPU1_ERR1_LVC1_R_N")
	)
	(segment
		(start 81.383378 -229.58679)
		(end 77.14742 -225.350832)
		(width 0.12954)
		(layer "B.Cu")
		(net "H_CPU1_ERR1_LVC1_R_N")
	)
	(segment
		(start 102.994968 -231.224836)
		(end 102.986078 -231.219756)
		(width 0.0889)
		(layer "B.Cu")
		(net "H_CPU1_ERR1_LVC1_R_N")
	)
	(segment
		(start 83.864958 -229.683056)
		(end 83.768692 -229.58679)
		(width 0.12954)
		(layer "B.Cu")
		(net "H_CPU1_ERR1_LVC1_R_N")
	)
	(arc
		(start 96.416368 -229.597204)
		(mid 96.142169 -229.521369)
		(end 95.865696 -229.588568)
		(width 0.0889)
		(layer "B.Cu")
		(net "H_CPU1_ERR1_LVC1_R_N")
	)
	(arc
		(start 102.337362 -230.071168)
		(mid 102.257992 -229.797434)
		(end 102.055168 -229.597204)
		(width 0.0889)
		(layer "B.Cu")
		(net "H_CPU1_ERR1_LVC1_R_N")
	)
	(arc
		(start 95.476568 -229.597204)
		(mid 95.199755 -229.521334)
		(end 94.921324 -229.591108)
		(width 0.0889)
		(layer "B.Cu")
		(net "H_CPU1_ERR1_LVC1_R_N")
	)
	(arc
		(start 100.175568 -229.597204)
		(mid 99.901369 -229.521369)
		(end 99.624896 -229.588568)
		(width 0.0889)
		(layer "B.Cu")
		(net "H_CPU1_ERR1_LVC1_R_N")
	)
	(arc
		(start 88.332564 -229.597204)
		(mid 88.242292 -229.634803)
		(end 88.145366 -229.64775)
		(width 0.0889)
		(layer "B.Cu")
		(net "H_CPU1_ERR1_LVC1_R_N")
	)
	(arc
		(start 102.807516 -230.900478)
		(mid 102.733525 -230.620912)
		(end 102.53091 -230.414576)
		(width 0.0889)
		(layer "B.Cu")
		(net "H_CPU1_ERR1_LVC1_R_N")
	)
	(arc
		(start 94.536514 -229.597204)
		(mid 94.259955 -229.521461)
		(end 93.981778 -229.591108)
		(width 0.0889)
		(layer "B.Cu")
		(net "H_CPU1_ERR1_LVC1_R_N")
	)
	(arc
		(start 102.515924 -230.40594)
		(mid 102.38501 -230.26958)
		(end 102.337362 -230.086662)
		(width 0.0889)
		(layer "B.Cu")
		(net "H_CPU1_ERR1_LVC1_R_N")
	)
	(arc
		(start 94.91091 -229.597204)
		(mid 94.723712 -229.647347)
		(end 94.536514 -229.597204)
		(width 0.0889)
		(layer "B.Cu")
		(net "H_CPU1_ERR1_LVC1_R_N")
	)
	(arc
		(start 91.717368 -229.597204)
		(mid 91.443169 -229.521369)
		(end 91.166696 -229.588568)
		(width 0.0889)
		(layer "B.Cu")
		(net "H_CPU1_ERR1_LVC1_R_N")
	)
	(arc
		(start 103.317548 -231.249474)
		(mid 103.153452 -231.273821)
		(end 102.994968 -231.224836)
		(width 0.0889)
		(layer "B.Cu")
		(net "H_CPU1_ERR1_LVC1_R_N")
	)
	(arc
		(start 90.212164 -229.597204)
		(mid 90.024966 -229.647347)
		(end 89.837768 -229.597204)
		(width 0.0889)
		(layer "B.Cu")
		(net "H_CPU1_ERR1_LVC1_R_N")
	)
	(arc
		(start 99.610164 -229.597204)
		(mid 99.422966 -229.647347)
		(end 99.235768 -229.597204)
		(width 0.0889)
		(layer "B.Cu")
		(net "H_CPU1_ERR1_LVC1_R_N")
	)
	(arc
		(start 102.986078 -231.219756)
		(mid 102.855164 -231.083396)
		(end 102.807516 -230.900478)
		(width 0.0889)
		(layer "B.Cu")
		(net "H_CPU1_ERR1_LVC1_R_N")
	)
	(arc
		(start 101.115114 -229.597204)
		(mid 100.838555 -229.521461)
		(end 100.560378 -229.591108)
		(width 0.0889)
		(layer "B.Cu")
		(net "H_CPU1_ERR1_LVC1_R_N")
	)
	(arc
		(start 98.670364 -229.597204)
		(mid 98.483166 -229.647347)
		(end 98.295968 -229.597204)
		(width 0.0889)
		(layer "B.Cu")
		(net "H_CPU1_ERR1_LVC1_R_N")
	)
	(arc
		(start 99.235768 -229.597204)
		(mid 98.961569 -229.521369)
		(end 98.685096 -229.588568)
		(width 0.0889)
		(layer "B.Cu")
		(net "H_CPU1_ERR1_LVC1_R_N")
	)
	(arc
		(start 88.897968 -229.597204)
		(mid 88.623769 -229.521369)
		(end 88.347296 -229.588568)
		(width 0.0889)
		(layer "B.Cu")
		(net "H_CPU1_ERR1_LVC1_R_N")
	)
	(arc
		(start 97.356168 -229.597204)
		(mid 97.073466 -229.521428)
		(end 96.790764 -229.597204)
		(width 0.0889)
		(layer "B.Cu")
		(net "H_CPU1_ERR1_LVC1_R_N")
	)
	(arc
		(start 96.790764 -229.597204)
		(mid 96.603566 -229.647347)
		(end 96.416368 -229.597204)
		(width 0.0889)
		(layer "B.Cu")
		(net "H_CPU1_ERR1_LVC1_R_N")
	)
	(arc
		(start 97.730564 -229.597204)
		(mid 97.543366 -229.647347)
		(end 97.356168 -229.597204)
		(width 0.0889)
		(layer "B.Cu")
		(net "H_CPU1_ERR1_LVC1_R_N")
	)
	(arc
		(start 89.837768 -229.597204)
		(mid 89.563569 -229.521369)
		(end 89.287096 -229.588568)
		(width 0.0889)
		(layer "B.Cu")
		(net "H_CPU1_ERR1_LVC1_R_N")
	)
	(arc
		(start 92.657168 -229.597204)
		(mid 92.382969 -229.521369)
		(end 92.106496 -229.588568)
		(width 0.0889)
		(layer "B.Cu")
		(net "H_CPU1_ERR1_LVC1_R_N")
	)
	(arc
		(start 93.031564 -229.597204)
		(mid 92.844366 -229.647347)
		(end 92.657168 -229.597204)
		(width 0.0889)
		(layer "B.Cu")
		(net "H_CPU1_ERR1_LVC1_R_N")
	)
	(arc
		(start 100.549964 -229.597204)
		(mid 100.362766 -229.647347)
		(end 100.175568 -229.597204)
		(width 0.0889)
		(layer "B.Cu")
		(net "H_CPU1_ERR1_LVC1_R_N")
	)
	(arc
		(start 93.596968 -229.597204)
		(mid 93.322769 -229.521369)
		(end 93.046296 -229.588568)
		(width 0.0889)
		(layer "B.Cu")
		(net "H_CPU1_ERR1_LVC1_R_N")
	)
	(arc
		(start 89.272364 -229.597204)
		(mid 89.085166 -229.647347)
		(end 88.897968 -229.597204)
		(width 0.0889)
		(layer "B.Cu")
		(net "H_CPU1_ERR1_LVC1_R_N")
	)
	(arc
		(start 101.48951 -229.597204)
		(mid 101.302312 -229.647347)
		(end 101.115114 -229.597204)
		(width 0.0889)
		(layer "B.Cu")
		(net "H_CPU1_ERR1_LVC1_R_N")
	)
	(arc
		(start 98.295968 -229.597204)
		(mid 98.021769 -229.521369)
		(end 97.745296 -229.588568)
		(width 0.0889)
		(layer "B.Cu")
		(net "H_CPU1_ERR1_LVC1_R_N")
	)
	(arc
		(start 91.151964 -229.597204)
		(mid 90.964766 -229.647347)
		(end 90.777568 -229.597204)
		(width 0.0889)
		(layer "B.Cu")
		(net "H_CPU1_ERR1_LVC1_R_N")
	)
	(arc
		(start 90.777568 -229.597204)
		(mid 90.494866 -229.521428)
		(end 90.212164 -229.597204)
		(width 0.0889)
		(layer "B.Cu")
		(net "H_CPU1_ERR1_LVC1_R_N")
	)
	(arc
		(start 95.850964 -229.597204)
		(mid 95.663766 -229.647347)
		(end 95.476568 -229.597204)
		(width 0.0889)
		(layer "B.Cu")
		(net "H_CPU1_ERR1_LVC1_R_N")
	)
	(arc
		(start 102.055168 -229.597204)
		(mid 101.778355 -229.521334)
		(end 101.499924 -229.591108)
		(width 0.0889)
		(layer "B.Cu")
		(net "H_CPU1_ERR1_LVC1_R_N")
	)
	(arc
		(start 93.971364 -229.597204)
		(mid 93.784166 -229.647347)
		(end 93.596968 -229.597204)
		(width 0.0889)
		(layer "B.Cu")
		(net "H_CPU1_ERR1_LVC1_R_N")
	)
	(arc
		(start 92.091764 -229.597204)
		(mid 91.904566 -229.647347)
		(end 91.717368 -229.597204)
		(width 0.0889)
		(layer "B.Cu")
		(net "H_CPU1_ERR1_LVC1_R_N")
	)
	(segment
		(start 106.001312 -230.900732)
		(end 106.001566 -230.900478)
		(width 0.12954)
		(layer "F.Cu")
		(net "H_CPU1_ERR0_LVC1_R_N")
	)
	(segment
		(start 106.001312 -231.436418)
		(end 106.001312 -230.900732)
		(width 0.12954)
		(layer "F.Cu")
		(net "H_CPU1_ERR0_LVC1_R_N")
	)
	(via
		(at 82.188304 -204.28331)
		(size 0.6604)
		(drill 0.3302)
		(layers "F.Cu" "B.Cu")
		(net "H_CPU1_ERR0_LVC1_R_N")
	)
	(via
		(at 106.001566 -230.900478)
		(size 0.4572)
		(drill 0.2032)
		(layers "F.Cu" "B.Cu")
		(net "H_CPU1_ERR0_LVC1_R_N")
	)
	(segment
		(start 95.946468 -226.506786)
		(end 95.936054 -226.512882)
		(width 0.0889)
		(layer "B.Cu")
		(net "H_CPU1_ERR0_LVC1_R_N")
	)
	(segment
		(start 101.585014 -226.506786)
		(end 101.5746 -226.512882)
		(width 0.0889)
		(layer "B.Cu")
		(net "H_CPU1_ERR0_LVC1_R_N")
	)
	(segment
		(start 82.831178 -185.36285)
		(end 82.462624 -184.994296)
		(width 0.12954)
		(layer "B.Cu")
		(net "H_CPU1_ERR0_LVC1_R_N")
	)
	(segment
		(start 82.188304 -199.9742)
		(end 83.047078 -199.115426)
		(width 0.12954)
		(layer "B.Cu")
		(net "H_CPU1_ERR0_LVC1_R_N")
	)
	(segment
		(start 88.427814 -226.506786)
		(end 88.4174 -226.512882)
		(width 0.0889)
		(layer "B.Cu")
		(net "H_CPU1_ERR0_LVC1_R_N")
	)
	(segment
		(start 103.556816 -229.28834)
		(end 103.556816 -229.272846)
		(width 0.0889)
		(layer "B.Cu")
		(net "H_CPU1_ERR0_LVC1_R_N")
	)
	(segment
		(start 82.188304 -204.28331)
		(end 82.188304 -199.9742)
		(width 0.12954)
		(layer "B.Cu")
		(net "H_CPU1_ERR0_LVC1_R_N")
	)
	(segment
		(start 106.001566 -230.900478)
		(end 105.845102 -230.62946)
		(width 0.0889)
		(layer "B.Cu")
		(net "H_CPU1_ERR0_LVC1_R_N")
	)
	(segment
		(start 101.9683 -226.511866)
		(end 101.95941 -226.506786)
		(width 0.0889)
		(layer "B.Cu")
		(net "H_CPU1_ERR0_LVC1_R_N")
	)
	(segment
		(start 83.047078 -199.115426)
		(end 83.047078 -189.33795)
		(width 0.12954)
		(layer "B.Cu")
		(net "H_CPU1_ERR0_LVC1_R_N")
	)
	(segment
		(start 82.462624 -184.994296)
		(end 82.462624 -184.496202)
		(width 0.12954)
		(layer "B.Cu")
		(net "H_CPU1_ERR0_LVC1_R_N")
	)
	(segment
		(start 90.692224 -226.512882)
		(end 90.68181 -226.506786)
		(width 0.0889)
		(layer "B.Cu")
		(net "H_CPU1_ERR0_LVC1_R_N")
	)
	(segment
		(start 102.438454 -227.325682)
		(end 102.429564 -227.320602)
		(width 0.0889)
		(layer "B.Cu")
		(net "H_CPU1_ERR0_LVC1_R_N")
	)
	(segment
		(start 84.097368 -226.456748)
		(end 79.398368 -221.757748)
		(width 0.12954)
		(layer "B.Cu")
		(net "H_CPU1_ERR0_LVC1_R_N")
	)
	(segment
		(start 105.845102 -230.62946)
		(end 105.755948 -230.605584)
		(width 0.0889)
		(layer "B.Cu")
		(net "H_CPU1_ERR0_LVC1_R_N")
	)
	(segment
		(start 90.307414 -226.506786)
		(end 90.292682 -226.515422)
		(width 0.0889)
		(layer "B.Cu")
		(net "H_CPU1_ERR0_LVC1_R_N")
	)
	(segment
		(start 85.053424 -226.512882)
		(end 85.04301 -226.506786)
		(width 0.0889)
		(layer "B.Cu")
		(net "H_CPU1_ERR0_LVC1_R_N")
	)
	(segment
		(start 83.047078 -189.33795)
		(end 83.796378 -188.58865)
		(width 0.12954)
		(layer "B.Cu")
		(net "H_CPU1_ERR0_LVC1_R_N")
	)
	(segment
		(start 102.617016 -227.667058)
		(end 102.617016 -227.64496)
		(width 0.0889)
		(layer "B.Cu")
		(net "H_CPU1_ERR0_LVC1_R_N")
	)
	(segment
		(start 96.886014 -226.506786)
		(end 96.8756 -226.512882)
		(width 0.0889)
		(layer "B.Cu")
		(net "H_CPU1_ERR0_LVC1_R_N")
	)
	(segment
		(start 84.227162 -226.456748)
		(end 84.097368 -226.456748)
		(width 0.12954)
		(layer "B.Cu")
		(net "H_CPU1_ERR0_LVC1_R_N")
	)
	(segment
		(start 103.369364 -228.948488)
		(end 103.363268 -228.944932)
		(width 0.0889)
		(layer "B.Cu")
		(net "H_CPU1_ERR0_LVC1_R_N")
	)
	(segment
		(start 84.855812 -226.456748)
		(end 84.227162 -226.456748)
		(width 0.0889)
		(layer "B.Cu")
		(net "H_CPU1_ERR0_LVC1_R_N")
	)
	(segment
		(start 102.429564 -227.320602)
		(end 102.423468 -227.317046)
		(width 0.0889)
		(layer "B.Cu")
		(net "H_CPU1_ERR0_LVC1_R_N")
	)
	(segment
		(start 79.398368 -208.65592)
		(end 82.188304 -205.865984)
		(width 0.12954)
		(layer "B.Cu")
		(net "H_CPU1_ERR0_LVC1_R_N")
	)
	(segment
		(start 79.398368 -221.757748)
		(end 79.398368 -208.65592)
		(width 0.12954)
		(layer "B.Cu")
		(net "H_CPU1_ERR0_LVC1_R_N")
	)
	(segment
		(start 94.066614 -226.506786)
		(end 94.0562 -226.512882)
		(width 0.0889)
		(layer "B.Cu")
		(net "H_CPU1_ERR0_LVC1_R_N")
	)
	(segment
		(start 104.323896 -230.584756)
		(end 104.309164 -230.57612)
		(width 0.0889)
		(layer "B.Cu")
		(net "H_CPU1_ERR0_LVC1_R_N")
	)
	(segment
		(start 102.9081 -228.139752)
		(end 102.89921 -228.134672)
		(width 0.0889)
		(layer "B.Cu")
		(net "H_CPU1_ERR0_LVC1_R_N")
	)
	(segment
		(start 89.367614 -226.506786)
		(end 89.352882 -226.515422)
		(width 0.0889)
		(layer "B.Cu")
		(net "H_CPU1_ERR0_LVC1_R_N")
	)
	(segment
		(start 83.796378 -186.097164)
		(end 83.062064 -185.36285)
		(width 0.12954)
		(layer "B.Cu")
		(net "H_CPU1_ERR0_LVC1_R_N")
	)
	(segment
		(start 86.548214 -226.506786)
		(end 86.5378 -226.512882)
		(width 0.0889)
		(layer "B.Cu")
		(net "H_CPU1_ERR0_LVC1_R_N")
	)
	(segment
		(start 83.062064 -185.36285)
		(end 82.831178 -185.36285)
		(width 0.12954)
		(layer "B.Cu")
		(net "H_CPU1_ERR0_LVC1_R_N")
	)
	(segment
		(start 97.825814 -226.506786)
		(end 97.811082 -226.515422)
		(width 0.0889)
		(layer "B.Cu")
		(net "H_CPU1_ERR0_LVC1_R_N")
	)
	(segment
		(start 98.765868 -226.506786)
		(end 98.755454 -226.512882)
		(width 0.0889)
		(layer "B.Cu")
		(net "H_CPU1_ERR0_LVC1_R_N")
	)
	(segment
		(start 82.188304 -205.865984)
		(end 82.188304 -204.28331)
		(width 0.12954)
		(layer "B.Cu")
		(net "H_CPU1_ERR0_LVC1_R_N")
	)
	(segment
		(start 103.8479 -229.767384)
		(end 103.83901 -229.762304)
		(width 0.0889)
		(layer "B.Cu")
		(net "H_CPU1_ERR0_LVC1_R_N")
	)
	(segment
		(start 83.796378 -188.58865)
		(end 83.796378 -186.097164)
		(width 0.12954)
		(layer "B.Cu")
		(net "H_CPU1_ERR0_LVC1_R_N")
	)
	(segment
		(start 95.006414 -226.506786)
		(end 94.991682 -226.515422)
		(width 0.0889)
		(layer "B.Cu")
		(net "H_CPU1_ERR0_LVC1_R_N")
	)
	(segment
		(start 86.933024 -226.512882)
		(end 86.92261 -226.506786)
		(width 0.0889)
		(layer "B.Cu")
		(net "H_CPU1_ERR0_LVC1_R_N")
	)
	(segment
		(start 105.263696 -230.584756)
		(end 105.248964 -230.57612)
		(width 0.0889)
		(layer "B.Cu")
		(net "H_CPU1_ERR0_LVC1_R_N")
	)
	(segment
		(start 103.378254 -228.953568)
		(end 103.369364 -228.948488)
		(width 0.0889)
		(layer "B.Cu")
		(net "H_CPU1_ERR0_LVC1_R_N")
	)
	(segment
		(start 104.309164 -230.57612)
		(end 104.303068 -230.572564)
		(width 0.0889)
		(layer "B.Cu")
		(net "H_CPU1_ERR0_LVC1_R_N")
	)
	(arc
		(start 102.423468 -227.317046)
		(mid 102.220881 -227.110695)
		(end 102.146862 -226.831144)
		(width 0.0889)
		(layer "B.Cu")
		(net "H_CPU1_ERR0_LVC1_R_N")
	)
	(arc
		(start 94.991682 -226.515422)
		(mid 94.715207 -226.582742)
		(end 94.44101 -226.506786)
		(width 0.0889)
		(layer "B.Cu")
		(net "H_CPU1_ERR0_LVC1_R_N")
	)
	(arc
		(start 102.89921 -228.134672)
		(mid 102.697928 -227.937185)
		(end 102.617016 -227.667058)
		(width 0.0889)
		(layer "B.Cu")
		(net "H_CPU1_ERR0_LVC1_R_N")
	)
	(arc
		(start 101.95941 -226.506786)
		(mid 101.772212 -226.456643)
		(end 101.585014 -226.506786)
		(width 0.0889)
		(layer "B.Cu")
		(net "H_CPU1_ERR0_LVC1_R_N")
	)
	(arc
		(start 99.140264 -226.506786)
		(mid 98.953066 -226.456643)
		(end 98.765868 -226.506786)
		(width 0.0889)
		(layer "B.Cu")
		(net "H_CPU1_ERR0_LVC1_R_N")
	)
	(arc
		(start 100.080064 -226.506786)
		(mid 99.892866 -226.456643)
		(end 99.705668 -226.506786)
		(width 0.0889)
		(layer "B.Cu")
		(net "H_CPU1_ERR0_LVC1_R_N")
	)
	(arc
		(start 95.936054 -226.512882)
		(mid 95.657622 -226.582728)
		(end 95.38081 -226.506786)
		(width 0.0889)
		(layer "B.Cu")
		(net "H_CPU1_ERR0_LVC1_R_N")
	)
	(arc
		(start 89.74201 -226.506786)
		(mid 89.554812 -226.456643)
		(end 89.367614 -226.506786)
		(width 0.0889)
		(layer "B.Cu")
		(net "H_CPU1_ERR0_LVC1_R_N")
	)
	(arc
		(start 86.5378 -226.512882)
		(mid 86.259622 -226.582605)
		(end 85.983064 -226.506786)
		(width 0.0889)
		(layer "B.Cu")
		(net "H_CPU1_ERR0_LVC1_R_N")
	)
	(arc
		(start 103.363268 -228.944932)
		(mid 103.160681 -228.738581)
		(end 103.086662 -228.45903)
		(width 0.0889)
		(layer "B.Cu")
		(net "H_CPU1_ERR0_LVC1_R_N")
	)
	(arc
		(start 105.755948 -230.605584)
		(mid 105.507443 -230.651571)
		(end 105.263696 -230.584756)
		(width 0.0889)
		(layer "B.Cu")
		(net "H_CPU1_ERR0_LVC1_R_N")
	)
	(arc
		(start 96.320864 -226.506786)
		(mid 96.133666 -226.456643)
		(end 95.946468 -226.506786)
		(width 0.0889)
		(layer "B.Cu")
		(net "H_CPU1_ERR0_LVC1_R_N")
	)
	(arc
		(start 98.755454 -226.512882)
		(mid 98.477022 -226.582728)
		(end 98.20021 -226.506786)
		(width 0.0889)
		(layer "B.Cu")
		(net "H_CPU1_ERR0_LVC1_R_N")
	)
	(arc
		(start 90.292682 -226.515422)
		(mid 90.016207 -226.582742)
		(end 89.74201 -226.506786)
		(width 0.0889)
		(layer "B.Cu")
		(net "H_CPU1_ERR0_LVC1_R_N")
	)
	(arc
		(start 102.146862 -226.831144)
		(mid 102.099183 -226.648244)
		(end 101.9683 -226.511866)
		(width 0.0889)
		(layer "B.Cu")
		(net "H_CPU1_ERR0_LVC1_R_N")
	)
	(arc
		(start 96.8756 -226.512882)
		(mid 96.597422 -226.582605)
		(end 96.320864 -226.506786)
		(width 0.0889)
		(layer "B.Cu")
		(net "H_CPU1_ERR0_LVC1_R_N")
	)
	(arc
		(start 101.019864 -226.506786)
		(mid 100.832666 -226.456643)
		(end 100.645468 -226.506786)
		(width 0.0889)
		(layer "B.Cu")
		(net "H_CPU1_ERR0_LVC1_R_N")
	)
	(arc
		(start 105.248964 -230.57612)
		(mid 105.061766 -230.525977)
		(end 104.874568 -230.57612)
		(width 0.0889)
		(layer "B.Cu")
		(net "H_CPU1_ERR0_LVC1_R_N")
	)
	(arc
		(start 104.303068 -230.572564)
		(mid 104.100481 -230.366213)
		(end 104.026462 -230.086662)
		(width 0.0889)
		(layer "B.Cu")
		(net "H_CPU1_ERR0_LVC1_R_N")
	)
	(arc
		(start 98.20021 -226.506786)
		(mid 98.013012 -226.456643)
		(end 97.825814 -226.506786)
		(width 0.0889)
		(layer "B.Cu")
		(net "H_CPU1_ERR0_LVC1_R_N")
	)
	(arc
		(start 91.247468 -226.506786)
		(mid 90.970655 -226.582656)
		(end 90.692224 -226.512882)
		(width 0.0889)
		(layer "B.Cu")
		(net "H_CPU1_ERR0_LVC1_R_N")
	)
	(arc
		(start 85.983064 -226.506786)
		(mid 85.795866 -226.456643)
		(end 85.608668 -226.506786)
		(width 0.0889)
		(layer "B.Cu")
		(net "H_CPU1_ERR0_LVC1_R_N")
	)
	(arc
		(start 102.617016 -227.64496)
		(mid 102.569337 -227.46206)
		(end 102.438454 -227.325682)
		(width 0.0889)
		(layer "B.Cu")
		(net "H_CPU1_ERR0_LVC1_R_N")
	)
	(arc
		(start 88.4174 -226.512882)
		(mid 88.139222 -226.582605)
		(end 87.862664 -226.506786)
		(width 0.0889)
		(layer "B.Cu")
		(net "H_CPU1_ERR0_LVC1_R_N")
	)
	(arc
		(start 97.811082 -226.515422)
		(mid 97.534607 -226.582742)
		(end 97.26041 -226.506786)
		(width 0.0889)
		(layer "B.Cu")
		(net "H_CPU1_ERR0_LVC1_R_N")
	)
	(arc
		(start 92.187268 -226.506786)
		(mid 91.904566 -226.582562)
		(end 91.621864 -226.506786)
		(width 0.0889)
		(layer "B.Cu")
		(net "H_CPU1_ERR0_LVC1_R_N")
	)
	(arc
		(start 88.80221 -226.506786)
		(mid 88.615012 -226.456643)
		(end 88.427814 -226.506786)
		(width 0.0889)
		(layer "B.Cu")
		(net "H_CPU1_ERR0_LVC1_R_N")
	)
	(arc
		(start 100.645468 -226.506786)
		(mid 100.362766 -226.582562)
		(end 100.080064 -226.506786)
		(width 0.0889)
		(layer "B.Cu")
		(net "H_CPU1_ERR0_LVC1_R_N")
	)
	(arc
		(start 87.488268 -226.506786)
		(mid 87.211455 -226.582656)
		(end 86.933024 -226.512882)
		(width 0.0889)
		(layer "B.Cu")
		(net "H_CPU1_ERR0_LVC1_R_N")
	)
	(arc
		(start 91.621864 -226.506786)
		(mid 91.434666 -226.456643)
		(end 91.247468 -226.506786)
		(width 0.0889)
		(layer "B.Cu")
		(net "H_CPU1_ERR0_LVC1_R_N")
	)
	(arc
		(start 103.83901 -229.762304)
		(mid 103.636187 -229.562073)
		(end 103.556816 -229.28834)
		(width 0.0889)
		(layer "B.Cu")
		(net "H_CPU1_ERR0_LVC1_R_N")
	)
	(arc
		(start 94.0562 -226.512882)
		(mid 93.778022 -226.582605)
		(end 93.501464 -226.506786)
		(width 0.0889)
		(layer "B.Cu")
		(net "H_CPU1_ERR0_LVC1_R_N")
	)
	(arc
		(start 86.92261 -226.506786)
		(mid 86.735412 -226.456643)
		(end 86.548214 -226.506786)
		(width 0.0889)
		(layer "B.Cu")
		(net "H_CPU1_ERR0_LVC1_R_N")
	)
	(arc
		(start 94.44101 -226.506786)
		(mid 94.253812 -226.456643)
		(end 94.066614 -226.506786)
		(width 0.0889)
		(layer "B.Cu")
		(net "H_CPU1_ERR0_LVC1_R_N")
	)
	(arc
		(start 97.26041 -226.506786)
		(mid 97.073212 -226.456643)
		(end 96.886014 -226.506786)
		(width 0.0889)
		(layer "B.Cu")
		(net "H_CPU1_ERR0_LVC1_R_N")
	)
	(arc
		(start 104.026462 -230.086662)
		(mid 103.978783 -229.903762)
		(end 103.8479 -229.767384)
		(width 0.0889)
		(layer "B.Cu")
		(net "H_CPU1_ERR0_LVC1_R_N")
	)
	(arc
		(start 85.04301 -226.506786)
		(mid 84.952703 -226.469457)
		(end 84.855812 -226.456748)
		(width 0.0889)
		(layer "B.Cu")
		(net "H_CPU1_ERR0_LVC1_R_N")
	)
	(arc
		(start 87.862664 -226.506786)
		(mid 87.675466 -226.456643)
		(end 87.488268 -226.506786)
		(width 0.0889)
		(layer "B.Cu")
		(net "H_CPU1_ERR0_LVC1_R_N")
	)
	(arc
		(start 89.352882 -226.515422)
		(mid 89.076407 -226.582742)
		(end 88.80221 -226.506786)
		(width 0.0889)
		(layer "B.Cu")
		(net "H_CPU1_ERR0_LVC1_R_N")
	)
	(arc
		(start 85.608668 -226.506786)
		(mid 85.331855 -226.582656)
		(end 85.053424 -226.512882)
		(width 0.0889)
		(layer "B.Cu")
		(net "H_CPU1_ERR0_LVC1_R_N")
	)
	(arc
		(start 92.561664 -226.506786)
		(mid 92.374466 -226.456643)
		(end 92.187268 -226.506786)
		(width 0.0889)
		(layer "B.Cu")
		(net "H_CPU1_ERR0_LVC1_R_N")
	)
	(arc
		(start 104.874568 -230.57612)
		(mid 104.600369 -230.651955)
		(end 104.323896 -230.584756)
		(width 0.0889)
		(layer "B.Cu")
		(net "H_CPU1_ERR0_LVC1_R_N")
	)
	(arc
		(start 101.5746 -226.512882)
		(mid 101.296422 -226.582605)
		(end 101.019864 -226.506786)
		(width 0.0889)
		(layer "B.Cu")
		(net "H_CPU1_ERR0_LVC1_R_N")
	)
	(arc
		(start 95.38081 -226.506786)
		(mid 95.193612 -226.456643)
		(end 95.006414 -226.506786)
		(width 0.0889)
		(layer "B.Cu")
		(net "H_CPU1_ERR0_LVC1_R_N")
	)
	(arc
		(start 93.501464 -226.506786)
		(mid 93.314266 -226.456643)
		(end 93.127068 -226.506786)
		(width 0.0889)
		(layer "B.Cu")
		(net "H_CPU1_ERR0_LVC1_R_N")
	)
	(arc
		(start 103.086662 -228.45903)
		(mid 103.038983 -228.27613)
		(end 102.9081 -228.139752)
		(width 0.0889)
		(layer "B.Cu")
		(net "H_CPU1_ERR0_LVC1_R_N")
	)
	(arc
		(start 99.705668 -226.506786)
		(mid 99.422966 -226.582562)
		(end 99.140264 -226.506786)
		(width 0.0889)
		(layer "B.Cu")
		(net "H_CPU1_ERR0_LVC1_R_N")
	)
	(arc
		(start 103.556816 -229.272846)
		(mid 103.509137 -229.089946)
		(end 103.378254 -228.953568)
		(width 0.0889)
		(layer "B.Cu")
		(net "H_CPU1_ERR0_LVC1_R_N")
	)
	(arc
		(start 93.127068 -226.506786)
		(mid 92.844366 -226.582562)
		(end 92.561664 -226.506786)
		(width 0.0889)
		(layer "B.Cu")
		(net "H_CPU1_ERR0_LVC1_R_N")
	)
	(arc
		(start 90.68181 -226.506786)
		(mid 90.494612 -226.456643)
		(end 90.307414 -226.506786)
		(width 0.0889)
		(layer "B.Cu")
		(net "H_CPU1_ERR0_LVC1_R_N")
	)
	(segment
		(start 109.760512 -233.064304)
		(end 109.760512 -232.528618)
		(width 0.12954)
		(layer "F.Cu")
		(net "H_CPU1_CATERR_LVC1_R_N")
	)
	(segment
		(start 109.760512 -232.528618)
		(end 109.760766 -232.528364)
		(width 0.12954)
		(layer "F.Cu")
		(net "H_CPU1_CATERR_LVC1_R_N")
	)
	(via
		(at 109.760766 -232.528364)
		(size 0.4572)
		(drill 0.2032)
		(layers "F.Cu" "B.Cu")
		(net "H_CPU1_CATERR_LVC1_R_N")
	)
	(via
		(at 73.440798 -186.75985)
		(size 0.508)
		(drill 0.254)
		(layers "F.Cu" "B.Cu")
		(net "H_CPU1_CATERR_LVC1_R_N")
	)
	(segment
		(start 73.612248 -182.358284)
		(end 73.612248 -186.5884)
		(width 0.12954)
		(layer "B.Cu")
		(net "H_CPU1_CATERR_LVC1_R_N")
	)
	(segment
		(start 73.902062 -182.2196)
		(end 73.750932 -182.2196)
		(width 0.12954)
		(layer "B.Cu")
		(net "H_CPU1_CATERR_LVC1_R_N")
	)
	(segment
		(start 73.750932 -182.2196)
		(end 73.612248 -182.358284)
		(width 0.12954)
		(layer "B.Cu")
		(net "H_CPU1_CATERR_LVC1_R_N")
	)
	(segment
		(start 73.612248 -186.5884)
		(end 73.440798 -186.75985)
		(width 0.12954)
		(layer "B.Cu")
		(net "H_CPU1_CATERR_LVC1_R_N")
	)
	(segment
		(start 96.805496 -226.33305)
		(end 96.790764 -226.341686)
		(width 0.0889)
		(layer "In4.Cu")
		(net "H_CPU1_CATERR_LVC1_R_N")
	)
	(segment
		(start 97.745296 -226.33305)
		(end 97.730564 -226.341686)
		(width 0.0889)
		(layer "In4.Cu")
		(net "H_CPU1_CATERR_LVC1_R_N")
	)
	(segment
		(start 86.234778 -216.90965)
		(end 85.457538 -216.13241)
		(width 0.0889)
		(layer "In4.Cu")
		(net "H_CPU1_CATERR_LVC1_R_N")
	)
	(segment
		(start 108.083096 -232.844086)
		(end 108.068364 -232.852722)
		(width 0.0889)
		(layer "In4.Cu")
		(net "H_CPU1_CATERR_LVC1_R_N")
	)
	(segment
		(start 107.143296 -232.844086)
		(end 107.128564 -232.852722)
		(width 0.0889)
		(layer "In4.Cu")
		(net "H_CPU1_CATERR_LVC1_R_N")
	)
	(segment
		(start 89.650316 -221.133924)
		(end 89.650316 -221.115382)
		(width 0.0889)
		(layer "In4.Cu")
		(net "H_CPU1_CATERR_LVC1_R_N")
	)
	(segment
		(start 102.524814 -227.155502)
		(end 102.515924 -227.150422)
		(width 0.0889)
		(layer "In4.Cu")
		(net "H_CPU1_CATERR_LVC1_R_N")
	)
	(segment
		(start 106.659172 -232.779824)
		(end 106.478578 -232.59923)
		(width 0.0889)
		(layer "In4.Cu")
		(net "H_CPU1_CATERR_LVC1_R_N")
	)
	(segment
		(start 109.604302 -232.799382)
		(end 109.515148 -232.823258)
		(width 0.0889)
		(layer "In4.Cu")
		(net "H_CPU1_CATERR_LVC1_R_N")
	)
	(segment
		(start 75.399138 -188.71819)
		(end 73.440798 -186.75985)
		(width 0.127)
		(layer "In4.Cu")
		(net "H_CPU1_CATERR_LVC1_R_N")
	)
	(segment
		(start 88.350344 -220.584776)
		(end 87.142828 -219.37726)
		(width 0.0889)
		(layer "In4.Cu")
		(net "H_CPU1_CATERR_LVC1_R_N")
	)
	(segment
		(start 104.3305 -228.813614)
		(end 103.588058 -227.46335)
		(width 0.0889)
		(layer "In4.Cu")
		(net "H_CPU1_CATERR_LVC1_R_N")
	)
	(segment
		(start 95.006414 -225.527616)
		(end 94.991682 -225.51898)
		(width 0.0889)
		(layer "In4.Cu")
		(net "H_CPU1_CATERR_LVC1_R_N")
	)
	(segment
		(start 89.837768 -223.085914)
		(end 89.828878 -223.080834)
		(width 0.0889)
		(layer "In4.Cu")
		(net "H_CPU1_CATERR_LVC1_R_N")
	)
	(segment
		(start 96.228916 -226.017328)
		(end 96.228916 -226.003104)
		(width 0.0889)
		(layer "In4.Cu")
		(net "H_CPU1_CATERR_LVC1_R_N")
	)
	(segment
		(start 103.017828 -227.22713)
		(end 102.782624 -227.22713)
		(width 0.0889)
		(layer "In4.Cu")
		(net "H_CPU1_CATERR_LVC1_R_N")
	)
	(segment
		(start 109.760766 -232.528364)
		(end 109.604302 -232.799382)
		(width 0.0889)
		(layer "In4.Cu")
		(net "H_CPU1_CATERR_LVC1_R_N")
	)
	(segment
		(start 89.837768 -224.7138)
		(end 89.828878 -224.70872)
		(width 0.0889)
		(layer "In4.Cu")
		(net "H_CPU1_CATERR_LVC1_R_N")
	)
	(segment
		(start 87.142828 -219.37726)
		(end 86.648798 -218.18473)
		(width 0.0889)
		(layer "In4.Cu")
		(net "H_CPU1_CATERR_LVC1_R_N")
	)
	(segment
		(start 91.247214 -225.527616)
		(end 91.238324 -225.522536)
		(width 0.0889)
		(layer "In4.Cu")
		(net "H_CPU1_CATERR_LVC1_R_N")
	)
	(segment
		(start 90.119962 -221.963234)
		(end 90.119962 -221.932246)
		(width 0.0889)
		(layer "In4.Cu")
		(net "H_CPU1_CATERR_LVC1_R_N")
	)
	(segment
		(start 86.234778 -217.29827)
		(end 86.234778 -216.90965)
		(width 0.0889)
		(layer "In4.Cu")
		(net "H_CPU1_CATERR_LVC1_R_N")
	)
	(segment
		(start 95.946214 -225.527616)
		(end 95.931482 -225.51898)
		(width 0.0889)
		(layer "In4.Cu")
		(net "H_CPU1_CATERR_LVC1_R_N")
	)
	(segment
		(start 94.066614 -225.527616)
		(end 94.051882 -225.51898)
		(width 0.0889)
		(layer "In4.Cu")
		(net "H_CPU1_CATERR_LVC1_R_N")
	)
	(segment
		(start 92.187014 -225.527616)
		(end 92.172282 -225.51898)
		(width 0.0889)
		(layer "In4.Cu")
		(net "H_CPU1_CATERR_LVC1_R_N")
	)
	(segment
		(start 90.120216 -223.585532)
		(end 90.120216 -223.557084)
		(width 0.0889)
		(layer "In4.Cu")
		(net "H_CPU1_CATERR_LVC1_R_N")
	)
	(segment
		(start 85.457538 -216.13241)
		(end 75.399138 -191.849756)
		(width 0.127)
		(layer "In4.Cu")
		(net "H_CPU1_CATERR_LVC1_R_N")
	)
	(segment
		(start 109.022896 -232.844086)
		(end 109.008164 -232.852722)
		(width 0.0889)
		(layer "In4.Cu")
		(net "H_CPU1_CATERR_LVC1_R_N")
	)
	(segment
		(start 86.648798 -218.18473)
		(end 86.648798 -217.71229)
		(width 0.0889)
		(layer "In4.Cu")
		(net "H_CPU1_CATERR_LVC1_R_N")
	)
	(segment
		(start 102.337362 -226.831144)
		(end 102.337362 -226.81565)
		(width 0.0889)
		(layer "In4.Cu")
		(net "H_CPU1_CATERR_LVC1_R_N")
	)
	(segment
		(start 102.53091 -227.159058)
		(end 102.524814 -227.155502)
		(width 0.0889)
		(layer "In4.Cu")
		(net "H_CPU1_CATERR_LVC1_R_N")
	)
	(segment
		(start 96.416368 -226.341686)
		(end 96.407478 -226.336606)
		(width 0.0889)
		(layer "In4.Cu")
		(net "H_CPU1_CATERR_LVC1_R_N")
	)
	(segment
		(start 89.828878 -222.442278)
		(end 89.837768 -222.437198)
		(width 0.0889)
		(layer "In4.Cu")
		(net "H_CPU1_CATERR_LVC1_R_N")
	)
	(segment
		(start 93.126814 -225.527616)
		(end 93.112082 -225.51898)
		(width 0.0889)
		(layer "In4.Cu")
		(net "H_CPU1_CATERR_LVC1_R_N")
	)
	(segment
		(start 91.059762 -225.203258)
		(end 91.059762 -225.187764)
		(width 0.0889)
		(layer "In4.Cu")
		(net "H_CPU1_CATERR_LVC1_R_N")
	)
	(segment
		(start 89.837768 -221.458282)
		(end 89.828878 -221.453202)
		(width 0.0889)
		(layer "In4.Cu")
		(net "H_CPU1_CATERR_LVC1_R_N")
	)
	(segment
		(start 106.478578 -232.59923)
		(end 106.048302 -231.864662)
		(width 0.0889)
		(layer "In4.Cu")
		(net "H_CPU1_CATERR_LVC1_R_N")
	)
	(segment
		(start 86.648798 -217.71229)
		(end 86.234778 -217.29827)
		(width 0.0889)
		(layer "In4.Cu")
		(net "H_CPU1_CATERR_LVC1_R_N")
	)
	(segment
		(start 101.504496 -226.33305)
		(end 101.489764 -226.341686)
		(width 0.0889)
		(layer "In4.Cu")
		(net "H_CPU1_CATERR_LVC1_R_N")
	)
	(segment
		(start 106.048302 -231.864662)
		(end 104.3305 -228.813614)
		(width 0.0889)
		(layer "In4.Cu")
		(net "H_CPU1_CATERR_LVC1_R_N")
	)
	(segment
		(start 75.399138 -191.849756)
		(end 75.399138 -188.71819)
		(width 0.127)
		(layer "In4.Cu")
		(net "H_CPU1_CATERR_LVC1_R_N")
	)
	(segment
		(start 90.226896 -224.705164)
		(end 90.212164 -224.7138)
		(width 0.0889)
		(layer "In4.Cu")
		(net "H_CPU1_CATERR_LVC1_R_N")
	)
	(segment
		(start 89.828878 -224.070164)
		(end 89.837768 -224.065084)
		(width 0.0889)
		(layer "In4.Cu")
		(net "H_CPU1_CATERR_LVC1_R_N")
	)
	(arc
		(start 91.238324 -225.522536)
		(mid 91.10741 -225.386176)
		(end 91.059762 -225.203258)
		(width 0.0889)
		(layer "In4.Cu")
		(net "H_CPU1_CATERR_LVC1_R_N")
	)
	(arc
		(start 91.059762 -225.187764)
		(mid 90.980392 -224.91403)
		(end 90.777568 -224.7138)
		(width 0.0889)
		(layer "In4.Cu")
		(net "H_CPU1_CATERR_LVC1_R_N")
	)
	(arc
		(start 89.828878 -224.70872)
		(mid 89.650281 -224.389442)
		(end 89.828878 -224.070164)
		(width 0.0889)
		(layer "In4.Cu")
		(net "H_CPU1_CATERR_LVC1_R_N")
	)
	(arc
		(start 91.62161 -225.527616)
		(mid 91.434412 -225.577759)
		(end 91.247214 -225.527616)
		(width 0.0889)
		(layer "In4.Cu")
		(net "H_CPU1_CATERR_LVC1_R_N")
	)
	(arc
		(start 101.115368 -226.341686)
		(mid 100.832666 -226.26591)
		(end 100.549964 -226.341686)
		(width 0.0889)
		(layer "In4.Cu")
		(net "H_CPU1_CATERR_LVC1_R_N")
	)
	(arc
		(start 96.790764 -226.341686)
		(mid 96.603566 -226.391829)
		(end 96.416368 -226.341686)
		(width 0.0889)
		(layer "In4.Cu")
		(net "H_CPU1_CATERR_LVC1_R_N")
	)
	(arc
		(start 96.228916 -226.003104)
		(mid 96.149697 -225.728419)
		(end 95.946214 -225.527616)
		(width 0.0889)
		(layer "In4.Cu")
		(net "H_CPU1_CATERR_LVC1_R_N")
	)
	(arc
		(start 92.172282 -225.51898)
		(mid 91.895841 -225.451814)
		(end 91.62161 -225.527616)
		(width 0.0889)
		(layer "In4.Cu")
		(net "H_CPU1_CATERR_LVC1_R_N")
	)
	(arc
		(start 98.295968 -226.341686)
		(mid 98.021769 -226.265851)
		(end 97.745296 -226.33305)
		(width 0.0889)
		(layer "In4.Cu")
		(net "H_CPU1_CATERR_LVC1_R_N")
	)
	(arc
		(start 88.802464 -220.644212)
		(mid 88.615266 -220.694355)
		(end 88.428068 -220.644212)
		(width 0.0889)
		(layer "In4.Cu")
		(net "H_CPU1_CATERR_LVC1_R_N")
	)
	(arc
		(start 94.991682 -225.51898)
		(mid 94.715241 -225.451814)
		(end 94.44101 -225.527616)
		(width 0.0889)
		(layer "In4.Cu")
		(net "H_CPU1_CATERR_LVC1_R_N")
	)
	(arc
		(start 96.407478 -226.336606)
		(mid 96.276564 -226.200246)
		(end 96.228916 -226.017328)
		(width 0.0889)
		(layer "In4.Cu")
		(net "H_CPU1_CATERR_LVC1_R_N")
	)
	(arc
		(start 93.50121 -225.527616)
		(mid 93.314012 -225.577759)
		(end 93.126814 -225.527616)
		(width 0.0889)
		(layer "In4.Cu")
		(net "H_CPU1_CATERR_LVC1_R_N")
	)
	(arc
		(start 89.837768 -224.065084)
		(mid 90.042103 -223.862479)
		(end 90.120216 -223.585532)
		(width 0.0889)
		(layer "In4.Cu")
		(net "H_CPU1_CATERR_LVC1_R_N")
	)
	(arc
		(start 97.356168 -226.341686)
		(mid 97.081969 -226.265851)
		(end 96.805496 -226.33305)
		(width 0.0889)
		(layer "In4.Cu")
		(net "H_CPU1_CATERR_LVC1_R_N")
	)
	(arc
		(start 89.837768 -222.437198)
		(mid 90.040591 -222.236967)
		(end 90.119962 -221.963234)
		(width 0.0889)
		(layer "In4.Cu")
		(net "H_CPU1_CATERR_LVC1_R_N")
	)
	(arc
		(start 93.112082 -225.51898)
		(mid 92.835641 -225.451814)
		(end 92.56141 -225.527616)
		(width 0.0889)
		(layer "In4.Cu")
		(net "H_CPU1_CATERR_LVC1_R_N")
	)
	(arc
		(start 90.119962 -221.932246)
		(mid 90.040592 -221.658512)
		(end 89.837768 -221.458282)
		(width 0.0889)
		(layer "In4.Cu")
		(net "H_CPU1_CATERR_LVC1_R_N")
	)
	(arc
		(start 97.730564 -226.341686)
		(mid 97.543366 -226.391829)
		(end 97.356168 -226.341686)
		(width 0.0889)
		(layer "In4.Cu")
		(net "H_CPU1_CATERR_LVC1_R_N")
	)
	(arc
		(start 98.670364 -226.341686)
		(mid 98.483166 -226.391829)
		(end 98.295968 -226.341686)
		(width 0.0889)
		(layer "In4.Cu")
		(net "H_CPU1_CATERR_LVC1_R_N")
	)
	(arc
		(start 88.428068 -220.644212)
		(mid 88.387259 -220.61704)
		(end 88.350344 -220.584776)
		(width 0.0889)
		(layer "In4.Cu")
		(net "H_CPU1_CATERR_LVC1_R_N")
	)
	(arc
		(start 108.633768 -232.852722)
		(mid 108.359569 -232.776887)
		(end 108.083096 -232.844086)
		(width 0.0889)
		(layer "In4.Cu")
		(net "H_CPU1_CATERR_LVC1_R_N")
	)
	(arc
		(start 92.56141 -225.527616)
		(mid 92.374212 -225.577759)
		(end 92.187014 -225.527616)
		(width 0.0889)
		(layer "In4.Cu")
		(net "H_CPU1_CATERR_LVC1_R_N")
	)
	(arc
		(start 102.055168 -226.341686)
		(mid 101.780969 -226.265851)
		(end 101.504496 -226.33305)
		(width 0.0889)
		(layer "In4.Cu")
		(net "H_CPU1_CATERR_LVC1_R_N")
	)
	(arc
		(start 90.212164 -224.7138)
		(mid 90.024966 -224.763943)
		(end 89.837768 -224.7138)
		(width 0.0889)
		(layer "In4.Cu")
		(net "H_CPU1_CATERR_LVC1_R_N")
	)
	(arc
		(start 100.175568 -226.341686)
		(mid 99.892866 -226.26591)
		(end 99.610164 -226.341686)
		(width 0.0889)
		(layer "In4.Cu")
		(net "H_CPU1_CATERR_LVC1_R_N")
	)
	(arc
		(start 89.828878 -223.080834)
		(mid 89.650281 -222.761556)
		(end 89.828878 -222.442278)
		(width 0.0889)
		(layer "In4.Cu")
		(net "H_CPU1_CATERR_LVC1_R_N")
	)
	(arc
		(start 95.38081 -225.527616)
		(mid 95.193612 -225.577759)
		(end 95.006414 -225.527616)
		(width 0.0889)
		(layer "In4.Cu")
		(net "H_CPU1_CATERR_LVC1_R_N")
	)
	(arc
		(start 107.693968 -232.852722)
		(mid 107.419769 -232.776887)
		(end 107.143296 -232.844086)
		(width 0.0889)
		(layer "In4.Cu")
		(net "H_CPU1_CATERR_LVC1_R_N")
	)
	(arc
		(start 109.515148 -232.823258)
		(mid 109.266643 -232.777271)
		(end 109.022896 -232.844086)
		(width 0.0889)
		(layer "In4.Cu")
		(net "H_CPU1_CATERR_LVC1_R_N")
	)
	(arc
		(start 102.337362 -226.81565)
		(mid 102.257992 -226.541916)
		(end 102.055168 -226.341686)
		(width 0.0889)
		(layer "In4.Cu")
		(net "H_CPU1_CATERR_LVC1_R_N")
	)
	(arc
		(start 109.008164 -232.852722)
		(mid 108.820966 -232.902865)
		(end 108.633768 -232.852722)
		(width 0.0889)
		(layer "In4.Cu")
		(net "H_CPU1_CATERR_LVC1_R_N")
	)
	(arc
		(start 102.782624 -227.22713)
		(mid 102.652243 -227.209818)
		(end 102.53091 -227.159058)
		(width 0.0889)
		(layer "In4.Cu")
		(net "H_CPU1_CATERR_LVC1_R_N")
	)
	(arc
		(start 106.754168 -232.852722)
		(mid 106.704268 -232.819401)
		(end 106.659172 -232.779824)
		(width 0.0889)
		(layer "In4.Cu")
		(net "H_CPU1_CATERR_LVC1_R_N")
	)
	(arc
		(start 103.588058 -227.46335)
		(mid 103.326434 -227.288539)
		(end 103.017828 -227.22713)
		(width 0.0889)
		(layer "In4.Cu")
		(net "H_CPU1_CATERR_LVC1_R_N")
	)
	(arc
		(start 94.44101 -225.527616)
		(mid 94.253812 -225.577759)
		(end 94.066614 -225.527616)
		(width 0.0889)
		(layer "In4.Cu")
		(net "H_CPU1_CATERR_LVC1_R_N")
	)
	(arc
		(start 108.068364 -232.852722)
		(mid 107.881166 -232.902865)
		(end 107.693968 -232.852722)
		(width 0.0889)
		(layer "In4.Cu")
		(net "H_CPU1_CATERR_LVC1_R_N")
	)
	(arc
		(start 89.828878 -221.453202)
		(mid 89.697964 -221.316842)
		(end 89.650316 -221.133924)
		(width 0.0889)
		(layer "In4.Cu")
		(net "H_CPU1_CATERR_LVC1_R_N")
	)
	(arc
		(start 90.777568 -224.7138)
		(mid 90.503369 -224.637965)
		(end 90.226896 -224.705164)
		(width 0.0889)
		(layer "In4.Cu")
		(net "H_CPU1_CATERR_LVC1_R_N")
	)
	(arc
		(start 94.051882 -225.51898)
		(mid 93.775441 -225.451814)
		(end 93.50121 -225.527616)
		(width 0.0889)
		(layer "In4.Cu")
		(net "H_CPU1_CATERR_LVC1_R_N")
	)
	(arc
		(start 89.650316 -221.115382)
		(mid 89.570154 -220.843193)
		(end 89.367868 -220.644212)
		(width 0.0889)
		(layer "In4.Cu")
		(net "H_CPU1_CATERR_LVC1_R_N")
	)
	(arc
		(start 99.610164 -226.341686)
		(mid 99.422966 -226.391829)
		(end 99.235768 -226.341686)
		(width 0.0889)
		(layer "In4.Cu")
		(net "H_CPU1_CATERR_LVC1_R_N")
	)
	(arc
		(start 100.549964 -226.341686)
		(mid 100.362766 -226.391829)
		(end 100.175568 -226.341686)
		(width 0.0889)
		(layer "In4.Cu")
		(net "H_CPU1_CATERR_LVC1_R_N")
	)
	(arc
		(start 101.489764 -226.341686)
		(mid 101.302566 -226.391829)
		(end 101.115368 -226.341686)
		(width 0.0889)
		(layer "In4.Cu")
		(net "H_CPU1_CATERR_LVC1_R_N")
	)
	(arc
		(start 102.515924 -227.150422)
		(mid 102.38501 -227.014062)
		(end 102.337362 -226.831144)
		(width 0.0889)
		(layer "In4.Cu")
		(net "H_CPU1_CATERR_LVC1_R_N")
	)
	(arc
		(start 90.120216 -223.557084)
		(mid 90.040054 -223.284895)
		(end 89.837768 -223.085914)
		(width 0.0889)
		(layer "In4.Cu")
		(net "H_CPU1_CATERR_LVC1_R_N")
	)
	(arc
		(start 107.128564 -232.852722)
		(mid 106.941366 -232.902865)
		(end 106.754168 -232.852722)
		(width 0.0889)
		(layer "In4.Cu")
		(net "H_CPU1_CATERR_LVC1_R_N")
	)
	(arc
		(start 89.367868 -220.644212)
		(mid 89.085166 -220.56847)
		(end 88.802464 -220.644212)
		(width 0.0889)
		(layer "In4.Cu")
		(net "H_CPU1_CATERR_LVC1_R_N")
	)
	(arc
		(start 95.931482 -225.51898)
		(mid 95.655041 -225.451814)
		(end 95.38081 -225.527616)
		(width 0.0889)
		(layer "In4.Cu")
		(net "H_CPU1_CATERR_LVC1_R_N")
	)
	(arc
		(start 99.235768 -226.341686)
		(mid 98.953066 -226.26591)
		(end 98.670364 -226.341686)
		(width 0.0889)
		(layer "In4.Cu")
		(net "H_CPU1_CATERR_LVC1_R_N")
	)
	(segment
		(start 109.290866 -231.714802)
		(end 109.290612 -231.714548)
		(width 0.12954)
		(layer "F.Cu")
		(net "H_CPU1_BMCINIT_LVC1")
	)
	(segment
		(start 109.290866 -232.250488)
		(end 109.290866 -231.714802)
		(width 0.12954)
		(layer "F.Cu")
		(net "H_CPU1_BMCINIT_LVC1")
	)
	(via
		(at 109.290612 -231.714548)
		(size 0.4572)
		(drill 0.2032)
		(layers "F.Cu" "B.Cu")
		(net "H_CPU1_BMCINIT_LVC1")
	)
	(via
		(at 71.9709 -185.034682)
		(size 0.762)
		(drill 0.254)
		(layers "F.Cu" "B.Cu")
		(net "H_CPU1_BMCINIT_LVC1")
	)
	(segment
		(start 71.65848 -184.064148)
		(end 71.65848 -183.678068)
		(width 0.12954)
		(layer "B.Cu")
		(net "H_CPU1_BMCINIT_LVC1")
	)
	(segment
		(start 71.90867 -184.314338)
		(end 71.65848 -184.064148)
		(width 0.12954)
		(layer "B.Cu")
		(net "H_CPU1_BMCINIT_LVC1")
	)
	(segment
		(start 71.90867 -184.972452)
		(end 71.90867 -184.314338)
		(width 0.12954)
		(layer "B.Cu")
		(net "H_CPU1_BMCINIT_LVC1")
	)
	(segment
		(start 71.9709 -185.034682)
		(end 71.90867 -184.972452)
		(width 0.12954)
		(layer "B.Cu")
		(net "H_CPU1_BMCINIT_LVC1")
	)
	(segment
		(start 104.979216 -226.401376)
		(end 104.865678 -226.336606)
		(width 0.0889)
		(layer "In4.Cu")
		(net "H_CPU1_BMCINIT_LVC1")
	)
	(segment
		(start 91.717368 -221.458282)
		(end 91.708478 -221.453202)
		(width 0.0889)
		(layer "In4.Cu")
		(net "H_CPU1_BMCINIT_LVC1")
	)
	(segment
		(start 79.483966 -189.938406)
		(end 73.939908 -184.394348)
		(width 0.127)
		(layer "In4.Cu")
		(net "H_CPU1_BMCINIT_LVC1")
	)
	(segment
		(start 102.337616 -223.575626)
		(end 102.337616 -223.561402)
		(width 0.0889)
		(layer "In4.Cu")
		(net "H_CPU1_BMCINIT_LVC1")
	)
	(segment
		(start 108.272326 -228.990398)
		(end 107.967018 -228.68509)
		(width 0.0889)
		(layer "In4.Cu")
		(net "H_CPU1_BMCINIT_LVC1")
	)
	(segment
		(start 91.708478 -220.814646)
		(end 91.717368 -220.809566)
		(width 0.0889)
		(layer "In4.Cu")
		(net "H_CPU1_BMCINIT_LVC1")
	)
	(segment
		(start 87.746332 -214.875618)
		(end 87.743284 -214.87257)
		(width 0.0889)
		(layer "In4.Cu")
		(net "H_CPU1_BMCINIT_LVC1")
	)
	(segment
		(start 79.483966 -193.633598)
		(end 79.483966 -189.938406)
		(width 0.127)
		(layer "In4.Cu")
		(net "H_CPU1_BMCINIT_LVC1")
	)
	(segment
		(start 90.307414 -219.01658)
		(end 90.292682 -219.007944)
		(width 0.0889)
		(layer "In4.Cu")
		(net "H_CPU1_BMCINIT_LVC1")
	)
	(segment
		(start 88.897968 -218.202764)
		(end 88.889078 -218.197684)
		(width 0.0889)
		(layer "In4.Cu")
		(net "H_CPU1_BMCINIT_LVC1")
	)
	(segment
		(start 95.946214 -222.272098)
		(end 95.931482 -222.263462)
		(width 0.0889)
		(layer "In4.Cu")
		(net "H_CPU1_BMCINIT_LVC1")
	)
	(segment
		(start 94.066614 -222.272098)
		(end 94.051882 -222.263462)
		(width 0.0889)
		(layer "In4.Cu")
		(net "H_CPU1_BMCINIT_LVC1")
	)
	(segment
		(start 88.427814 -217.388694)
		(end 88.418924 -217.383614)
		(width 0.0889)
		(layer "In4.Cu")
		(net "H_CPU1_BMCINIT_LVC1")
	)
	(segment
		(start 89.180416 -218.700858)
		(end 89.180416 -218.682316)
		(width 0.0889)
		(layer "In4.Cu")
		(net "H_CPU1_BMCINIT_LVC1")
	)
	(segment
		(start 87.443056 -214.74811)
		(end 87.257382 -214.562436)
		(width 0.127)
		(layer "In4.Cu")
		(net "H_CPU1_BMCINIT_LVC1")
	)
	(segment
		(start 102.807516 -224.389442)
		(end 102.807516 -224.379536)
		(width 0.0889)
		(layer "In4.Cu")
		(net "H_CPU1_BMCINIT_LVC1")
	)
	(segment
		(start 92.229686 -221.51975)
		(end 91.948762 -221.51975)
		(width 0.0889)
		(layer "In4.Cu")
		(net "H_CPU1_BMCINIT_LVC1")
	)
	(segment
		(start 99.624896 -223.077278)
		(end 99.610164 -223.085914)
		(width 0.0889)
		(layer "In4.Cu")
		(net "H_CPU1_BMCINIT_LVC1")
	)
	(segment
		(start 104.687116 -226.017328)
		(end 104.687116 -226.003104)
		(width 0.0889)
		(layer "In4.Cu")
		(net "H_CPU1_BMCINIT_LVC1")
	)
	(segment
		(start 82.828638 -196.97827)
		(end 79.483966 -193.633598)
		(width 0.127)
		(layer "In4.Cu")
		(net "H_CPU1_BMCINIT_LVC1")
	)
	(segment
		(start 107.398058 -227.645214)
		(end 107.398058 -227.59543)
		(width 0.0889)
		(layer "In4.Cu")
		(net "H_CPU1_BMCINIT_LVC1")
	)
	(segment
		(start 103.277162 -225.203258)
		(end 103.277162 -225.187764)
		(width 0.0889)
		(layer "In4.Cu")
		(net "H_CPU1_BMCINIT_LVC1")
	)
	(segment
		(start 88.427814 -215.761062)
		(end 88.418924 -215.755982)
		(width 0.0889)
		(layer "In4.Cu")
		(net "H_CPU1_BMCINIT_LVC1")
	)
	(segment
		(start 97.745296 -223.077278)
		(end 97.730564 -223.085914)
		(width 0.0889)
		(layer "In4.Cu")
		(net "H_CPU1_BMCINIT_LVC1")
	)
	(segment
		(start 106.834178 -226.50069)
		(end 106.771186 -226.437698)
		(width 0.0889)
		(layer "In4.Cu")
		(net "H_CPU1_BMCINIT_LVC1")
	)
	(segment
		(start 88.710008 -216.266014)
		(end 88.710008 -216.235026)
		(width 0.0889)
		(layer "In4.Cu")
		(net "H_CPU1_BMCINIT_LVC1")
	)
	(segment
		(start 87.743284 -214.87257)
		(end 87.443056 -214.74811)
		(width 0.0889)
		(layer "In4.Cu")
		(net "H_CPU1_BMCINIT_LVC1")
	)
	(segment
		(start 102.525068 -223.899984)
		(end 102.516178 -223.894904)
		(width 0.0889)
		(layer "In4.Cu")
		(net "H_CPU1_BMCINIT_LVC1")
	)
	(segment
		(start 101.504496 -223.077278)
		(end 101.489764 -223.085914)
		(width 0.0889)
		(layer "In4.Cu")
		(net "H_CPU1_BMCINIT_LVC1")
	)
	(segment
		(start 107.29214 -227.339652)
		(end 107.103672 -227.151184)
		(width 0.0889)
		(layer "In4.Cu")
		(net "H_CPU1_BMCINIT_LVC1")
	)
	(segment
		(start 72.21855 -184.394348)
		(end 71.9709 -184.641998)
		(width 0.127)
		(layer "In4.Cu")
		(net "H_CPU1_BMCINIT_LVC1")
	)
	(segment
		(start 108.787438 -230.067358)
		(end 108.787438 -230.02621)
		(width 0.0889)
		(layer "In4.Cu")
		(net "H_CPU1_BMCINIT_LVC1")
	)
	(segment
		(start 82.828638 -203.87056)
		(end 82.828638 -196.97827)
		(width 0.127)
		(layer "In4.Cu")
		(net "H_CPU1_BMCINIT_LVC1")
	)
	(segment
		(start 102.994968 -224.7138)
		(end 102.986078 -224.70872)
		(width 0.0889)
		(layer "In4.Cu")
		(net "H_CPU1_BMCINIT_LVC1")
	)
	(segment
		(start 88.240362 -215.436704)
		(end 88.240362 -215.418162)
		(width 0.0889)
		(layer "In4.Cu")
		(net "H_CPU1_BMCINIT_LVC1")
	)
	(segment
		(start 93.085666 -222.244412)
		(end 92.922598 -222.118936)
		(width 0.0889)
		(layer "In4.Cu")
		(net "H_CPU1_BMCINIT_LVC1")
	)
	(segment
		(start 88.710516 -217.878406)
		(end 88.710516 -217.864182)
		(width 0.0889)
		(layer "In4.Cu")
		(net "H_CPU1_BMCINIT_LVC1")
	)
	(segment
		(start 108.658152 -229.714044)
		(end 108.511086 -229.566978)
		(width 0.0889)
		(layer "In4.Cu")
		(net "H_CPU1_BMCINIT_LVC1")
	)
	(segment
		(start 107.860338 -228.427534)
		(end 107.860338 -228.36505)
		(width 0.0889)
		(layer "In4.Cu")
		(net "H_CPU1_BMCINIT_LVC1")
	)
	(segment
		(start 109.290612 -231.714548)
		(end 109.290612 -231.28224)
		(width 0.0889)
		(layer "In4.Cu")
		(net "H_CPU1_BMCINIT_LVC1")
	)
	(segment
		(start 73.939908 -184.394348)
		(end 72.21855 -184.394348)
		(width 0.127)
		(layer "In4.Cu")
		(net "H_CPU1_BMCINIT_LVC1")
	)
	(segment
		(start 87.257382 -214.562436)
		(end 82.828638 -203.87056)
		(width 0.127)
		(layer "In4.Cu")
		(net "H_CPU1_BMCINIT_LVC1")
	)
	(segment
		(start 107.7849 -228.182932)
		(end 107.504738 -227.90277)
		(width 0.0889)
		(layer "In4.Cu")
		(net "H_CPU1_BMCINIT_LVC1")
	)
	(segment
		(start 88.418924 -216.745058)
		(end 88.427814 -216.739978)
		(width 0.0889)
		(layer "In4.Cu")
		(net "H_CPU1_BMCINIT_LVC1")
	)
	(segment
		(start 95.006414 -222.272098)
		(end 94.991682 -222.263462)
		(width 0.0889)
		(layer "In4.Cu")
		(net "H_CPU1_BMCINIT_LVC1")
	)
	(segment
		(start 71.9709 -184.641998)
		(end 71.9709 -185.034682)
		(width 0.127)
		(layer "In4.Cu")
		(net "H_CPU1_BMCINIT_LVC1")
	)
	(segment
		(start 91.717368 -219.830396)
		(end 91.708478 -219.825316)
		(width 0.0889)
		(layer "In4.Cu")
		(net "H_CPU1_BMCINIT_LVC1")
	)
	(segment
		(start 105.760774 -226.41433)
		(end 105.585768 -226.41433)
		(width 0.0889)
		(layer "In4.Cu")
		(net "H_CPU1_BMCINIT_LVC1")
	)
	(arc
		(start 95.931482 -222.263462)
		(mid 95.655007 -222.196142)
		(end 95.38081 -222.272098)
		(width 0.0889)
		(layer "In4.Cu")
		(net "H_CPU1_BMCINIT_LVC1")
	)
	(arc
		(start 94.44101 -222.272098)
		(mid 94.253812 -222.322241)
		(end 94.066614 -222.272098)
		(width 0.0889)
		(layer "In4.Cu")
		(net "H_CPU1_BMCINIT_LVC1")
	)
	(arc
		(start 108.853478 -230.22687)
		(mid 108.804578 -230.153685)
		(end 108.787438 -230.067358)
		(width 0.0889)
		(layer "In4.Cu")
		(net "H_CPU1_BMCINIT_LVC1")
	)
	(arc
		(start 98.670364 -223.085914)
		(mid 98.483166 -223.136057)
		(end 98.295968 -223.085914)
		(width 0.0889)
		(layer "In4.Cu")
		(net "H_CPU1_BMCINIT_LVC1")
	)
	(arc
		(start 94.051882 -222.263462)
		(mid 93.775407 -222.196142)
		(end 93.50121 -222.272098)
		(width 0.0889)
		(layer "In4.Cu")
		(net "H_CPU1_BMCINIT_LVC1")
	)
	(arc
		(start 90.292682 -219.007944)
		(mid 90.016207 -218.940624)
		(end 89.74201 -219.01658)
		(width 0.0889)
		(layer "In4.Cu")
		(net "H_CPU1_BMCINIT_LVC1")
	)
	(arc
		(start 88.427814 -216.739978)
		(mid 88.630637 -216.539747)
		(end 88.710008 -216.266014)
		(width 0.0889)
		(layer "In4.Cu")
		(net "H_CPU1_BMCINIT_LVC1")
	)
	(arc
		(start 105.585768 -226.41433)
		(mid 105.400746 -226.421903)
		(end 105.21696 -226.444556)
		(width 0.0889)
		(layer "In4.Cu")
		(net "H_CPU1_BMCINIT_LVC1")
	)
	(arc
		(start 90.68181 -219.01658)
		(mid 90.494612 -219.066723)
		(end 90.307414 -219.01658)
		(width 0.0889)
		(layer "In4.Cu")
		(net "H_CPU1_BMCINIT_LVC1")
	)
	(arc
		(start 91.708478 -221.453202)
		(mid 91.529881 -221.133924)
		(end 91.708478 -220.814646)
		(width 0.0889)
		(layer "In4.Cu")
		(net "H_CPU1_BMCINIT_LVC1")
	)
	(arc
		(start 97.168716 -222.761556)
		(mid 96.885972 -222.271877)
		(end 96.32061 -222.272098)
		(width 0.0889)
		(layer "In4.Cu")
		(net "H_CPU1_BMCINIT_LVC1")
	)
	(arc
		(start 103.83901 -225.527616)
		(mid 103.464535 -225.52757)
		(end 103.277162 -225.203258)
		(width 0.0889)
		(layer "In4.Cu")
		(net "H_CPU1_BMCINIT_LVC1")
	)
	(arc
		(start 96.32061 -222.272098)
		(mid 96.133412 -222.322241)
		(end 95.946214 -222.272098)
		(width 0.0889)
		(layer "In4.Cu")
		(net "H_CPU1_BMCINIT_LVC1")
	)
	(arc
		(start 107.504738 -227.90277)
		(mid 107.425781 -227.784602)
		(end 107.398058 -227.645214)
		(width 0.0889)
		(layer "In4.Cu")
		(net "H_CPU1_BMCINIT_LVC1")
	)
	(arc
		(start 99.235768 -223.085914)
		(mid 98.953066 -223.010172)
		(end 98.670364 -223.085914)
		(width 0.0889)
		(layer "In4.Cu")
		(net "H_CPU1_BMCINIT_LVC1")
	)
	(arc
		(start 102.986078 -224.70872)
		(mid 102.855164 -224.57236)
		(end 102.807516 -224.389442)
		(width 0.0889)
		(layer "In4.Cu")
		(net "H_CPU1_BMCINIT_LVC1")
	)
	(arc
		(start 89.74201 -219.01658)
		(mid 89.371287 -219.018672)
		(end 89.180416 -218.700858)
		(width 0.0889)
		(layer "In4.Cu")
		(net "H_CPU1_BMCINIT_LVC1")
	)
	(arc
		(start 108.353098 -229.18547)
		(mid 108.332101 -229.079909)
		(end 108.272326 -228.990398)
		(width 0.0889)
		(layer "In4.Cu")
		(net "H_CPU1_BMCINIT_LVC1")
	)
	(arc
		(start 105.21696 -226.444556)
		(mid 105.094382 -226.443394)
		(end 104.979216 -226.401376)
		(width 0.0889)
		(layer "In4.Cu")
		(net "H_CPU1_BMCINIT_LVC1")
	)
	(arc
		(start 107.398058 -227.59543)
		(mid 107.370526 -227.457015)
		(end 107.29214 -227.339652)
		(width 0.0889)
		(layer "In4.Cu")
		(net "H_CPU1_BMCINIT_LVC1")
	)
	(arc
		(start 107.967018 -228.68509)
		(mid 107.888061 -228.566922)
		(end 107.860338 -228.427534)
		(width 0.0889)
		(layer "In4.Cu")
		(net "H_CPU1_BMCINIT_LVC1")
	)
	(arc
		(start 91.708478 -219.825316)
		(mid 91.577564 -219.688956)
		(end 91.529916 -219.506038)
		(width 0.0889)
		(layer "In4.Cu")
		(net "H_CPU1_BMCINIT_LVC1")
	)
	(arc
		(start 88.418924 -215.755982)
		(mid 88.28801 -215.619622)
		(end 88.240362 -215.436704)
		(width 0.0889)
		(layer "In4.Cu")
		(net "H_CPU1_BMCINIT_LVC1")
	)
	(arc
		(start 88.710516 -217.864182)
		(mid 88.631297 -217.589497)
		(end 88.427814 -217.388694)
		(width 0.0889)
		(layer "In4.Cu")
		(net "H_CPU1_BMCINIT_LVC1")
	)
	(arc
		(start 108.787438 -230.02621)
		(mid 108.753834 -229.857274)
		(end 108.658152 -229.714044)
		(width 0.0889)
		(layer "In4.Cu")
		(net "H_CPU1_BMCINIT_LVC1")
	)
	(arc
		(start 93.50121 -222.272098)
		(mid 93.333695 -222.321837)
		(end 93.161866 -222.290132)
		(width 0.0889)
		(layer "In4.Cu")
		(net "H_CPU1_BMCINIT_LVC1")
	)
	(arc
		(start 107.860338 -228.36505)
		(mid 107.840733 -228.266488)
		(end 107.7849 -228.182932)
		(width 0.0889)
		(layer "In4.Cu")
		(net "H_CPU1_BMCINIT_LVC1")
	)
	(arc
		(start 103.277162 -225.187764)
		(mid 103.197792 -224.91403)
		(end 102.994968 -224.7138)
		(width 0.0889)
		(layer "In4.Cu")
		(net "H_CPU1_BMCINIT_LVC1")
	)
	(arc
		(start 88.418924 -217.383614)
		(mid 88.240327 -217.064336)
		(end 88.418924 -216.745058)
		(width 0.0889)
		(layer "In4.Cu")
		(net "H_CPU1_BMCINIT_LVC1")
	)
	(arc
		(start 102.516178 -223.894904)
		(mid 102.385264 -223.758544)
		(end 102.337616 -223.575626)
		(width 0.0889)
		(layer "In4.Cu")
		(net "H_CPU1_BMCINIT_LVC1")
	)
	(arc
		(start 97.730564 -223.085914)
		(mid 97.356089 -223.085868)
		(end 97.168716 -222.761556)
		(width 0.0889)
		(layer "In4.Cu")
		(net "H_CPU1_BMCINIT_LVC1")
	)
	(arc
		(start 92.922598 -222.118936)
		(mid 92.830647 -222.018807)
		(end 92.777564 -221.893638)
		(width 0.0889)
		(layer "In4.Cu")
		(net "H_CPU1_BMCINIT_LVC1")
	)
	(arc
		(start 100.175568 -223.085914)
		(mid 99.901339 -223.009989)
		(end 99.624896 -223.077278)
		(width 0.0889)
		(layer "In4.Cu")
		(net "H_CPU1_BMCINIT_LVC1")
	)
	(arc
		(start 92.671138 -221.70263)
		(mid 92.468598 -221.567297)
		(end 92.229686 -221.51975)
		(width 0.0889)
		(layer "In4.Cu")
		(net "H_CPU1_BMCINIT_LVC1")
	)
	(arc
		(start 91.529916 -219.506038)
		(mid 91.247172 -219.016359)
		(end 90.68181 -219.01658)
		(width 0.0889)
		(layer "In4.Cu")
		(net "H_CPU1_BMCINIT_LVC1")
	)
	(arc
		(start 104.687116 -226.003104)
		(mid 104.398334 -225.524008)
		(end 103.83901 -225.527616)
		(width 0.0889)
		(layer "In4.Cu")
		(net "H_CPU1_BMCINIT_LVC1")
	)
	(arc
		(start 106.19613 -226.437698)
		(mid 106.07691 -226.495601)
		(end 105.947464 -226.467162)
		(width 0.0889)
		(layer "In4.Cu")
		(net "H_CPU1_BMCINIT_LVC1")
	)
	(arc
		(start 99.610164 -223.085914)
		(mid 99.422966 -223.136057)
		(end 99.235768 -223.085914)
		(width 0.0889)
		(layer "In4.Cu")
		(net "H_CPU1_BMCINIT_LVC1")
	)
	(arc
		(start 104.865678 -226.336606)
		(mid 104.734764 -226.200246)
		(end 104.687116 -226.017328)
		(width 0.0889)
		(layer "In4.Cu")
		(net "H_CPU1_BMCINIT_LVC1")
	)
	(arc
		(start 105.947464 -226.467162)
		(mid 105.857793 -226.427747)
		(end 105.760774 -226.41433)
		(width 0.0889)
		(layer "In4.Cu")
		(net "H_CPU1_BMCINIT_LVC1")
	)
	(arc
		(start 92.777564 -221.893638)
		(mid 92.737703 -221.790692)
		(end 92.671138 -221.70263)
		(width 0.0889)
		(layer "In4.Cu")
		(net "H_CPU1_BMCINIT_LVC1")
	)
	(arc
		(start 101.115368 -223.085914)
		(mid 100.832666 -223.010172)
		(end 100.549964 -223.085914)
		(width 0.0889)
		(layer "In4.Cu")
		(net "H_CPU1_BMCINIT_LVC1")
	)
	(arc
		(start 93.161866 -222.290132)
		(mid 93.122398 -222.269551)
		(end 93.085666 -222.244412)
		(width 0.0889)
		(layer "In4.Cu")
		(net "H_CPU1_BMCINIT_LVC1")
	)
	(arc
		(start 88.240362 -215.418162)
		(mid 88.093256 -215.055945)
		(end 87.746332 -214.875618)
		(width 0.0889)
		(layer "In4.Cu")
		(net "H_CPU1_BMCINIT_LVC1")
	)
	(arc
		(start 100.549964 -223.085914)
		(mid 100.362766 -223.136057)
		(end 100.175568 -223.085914)
		(width 0.0889)
		(layer "In4.Cu")
		(net "H_CPU1_BMCINIT_LVC1")
	)
	(arc
		(start 109.290612 -231.28224)
		(mid 109.177002 -230.711083)
		(end 108.853478 -230.22687)
		(width 0.0889)
		(layer "In4.Cu")
		(net "H_CPU1_BMCINIT_LVC1")
	)
	(arc
		(start 88.710008 -216.235026)
		(mid 88.630638 -215.961292)
		(end 88.427814 -215.761062)
		(width 0.0889)
		(layer "In4.Cu")
		(net "H_CPU1_BMCINIT_LVC1")
	)
	(arc
		(start 98.295968 -223.085914)
		(mid 98.021739 -223.009989)
		(end 97.745296 -223.077278)
		(width 0.0889)
		(layer "In4.Cu")
		(net "H_CPU1_BMCINIT_LVC1")
	)
	(arc
		(start 94.991682 -222.263462)
		(mid 94.715207 -222.196142)
		(end 94.44101 -222.272098)
		(width 0.0889)
		(layer "In4.Cu")
		(net "H_CPU1_BMCINIT_LVC1")
	)
	(arc
		(start 108.511086 -229.566978)
		(mid 108.394183 -229.391926)
		(end 108.353098 -229.18547)
		(width 0.0889)
		(layer "In4.Cu")
		(net "H_CPU1_BMCINIT_LVC1")
	)
	(arc
		(start 102.337616 -223.561402)
		(mid 102.056344 -223.086593)
		(end 101.504496 -223.077278)
		(width 0.0889)
		(layer "In4.Cu")
		(net "H_CPU1_BMCINIT_LVC1")
	)
	(arc
		(start 102.807516 -224.379536)
		(mid 102.729405 -224.102587)
		(end 102.525068 -223.899984)
		(width 0.0889)
		(layer "In4.Cu")
		(net "H_CPU1_BMCINIT_LVC1")
	)
	(arc
		(start 107.103672 -227.151184)
		(mid 107.013268 -227.015885)
		(end 106.981498 -226.85629)
		(width 0.0889)
		(layer "In4.Cu")
		(net "H_CPU1_BMCINIT_LVC1")
	)
	(arc
		(start 106.771186 -226.437698)
		(mid 106.483658 -226.3186)
		(end 106.19613 -226.437698)
		(width 0.0889)
		(layer "In4.Cu")
		(net "H_CPU1_BMCINIT_LVC1")
	)
	(arc
		(start 91.717368 -220.809566)
		(mid 91.9999 -220.320045)
		(end 91.717368 -219.830396)
		(width 0.0889)
		(layer "In4.Cu")
		(net "H_CPU1_BMCINIT_LVC1")
	)
	(arc
		(start 106.981498 -226.85629)
		(mid 106.943215 -226.663831)
		(end 106.834178 -226.50069)
		(width 0.0889)
		(layer "In4.Cu")
		(net "H_CPU1_BMCINIT_LVC1")
	)
	(arc
		(start 101.489764 -223.085914)
		(mid 101.302566 -223.136057)
		(end 101.115368 -223.085914)
		(width 0.0889)
		(layer "In4.Cu")
		(net "H_CPU1_BMCINIT_LVC1")
	)
	(arc
		(start 88.889078 -218.197684)
		(mid 88.758164 -218.061324)
		(end 88.710516 -217.878406)
		(width 0.0889)
		(layer "In4.Cu")
		(net "H_CPU1_BMCINIT_LVC1")
	)
	(arc
		(start 95.38081 -222.272098)
		(mid 95.193612 -222.322241)
		(end 95.006414 -222.272098)
		(width 0.0889)
		(layer "In4.Cu")
		(net "H_CPU1_BMCINIT_LVC1")
	)
	(arc
		(start 91.948762 -221.51975)
		(mid 91.829047 -221.504131)
		(end 91.717368 -221.458282)
		(width 0.0889)
		(layer "In4.Cu")
		(net "H_CPU1_BMCINIT_LVC1")
	)
	(arc
		(start 89.180416 -218.682316)
		(mid 89.102305 -218.405367)
		(end 88.897968 -218.202764)
		(width 0.0889)
		(layer "In4.Cu")
		(net "H_CPU1_BMCINIT_LVC1")
	)
	(segment
		(start 356.401116 -266.127992)
		(end 356.400862 -266.128246)
		(width 0.12954)
		(layer "F.Cu")
		(net "H_CPU0_THERMTRIP_LVC1_R_N")
	)
	(segment
		(start 119.43588 -97.264728)
		(end 120.3706 -96.330008)
		(width 0.12954)
		(layer "F.Cu")
		(net "H_CPU0_THERMTRIP_LVC1_R_N")
	)
	(segment
		(start 119.85244 -93.001338)
		(end 120.57888 -92.274898)
		(width 0.12954)
		(layer "F.Cu")
		(net "H_CPU0_THERMTRIP_LVC1_R_N")
	)
	(segment
		(start 119.43588 -98.770948)
		(end 119.43588 -97.264728)
		(width 0.12954)
		(layer "F.Cu")
		(net "H_CPU0_THERMTRIP_LVC1_R_N")
	)
	(segment
		(start 121.59488 -92.274898)
		(end 120.57888 -92.274898)
		(width 0.12954)
		(layer "F.Cu")
		(net "H_CPU0_THERMTRIP_LVC1_R_N")
	)
	(segment
		(start 119.85244 -94.097348)
		(end 119.85244 -93.001338)
		(width 0.12954)
		(layer "F.Cu")
		(net "H_CPU0_THERMTRIP_LVC1_R_N")
	)
	(segment
		(start 120.3706 -96.330008)
		(end 120.3706 -94.615508)
		(width 0.12954)
		(layer "F.Cu")
		(net "H_CPU0_THERMTRIP_LVC1_R_N")
	)
	(segment
		(start 356.401116 -265.592306)
		(end 356.401116 -266.127992)
		(width 0.12954)
		(layer "F.Cu")
		(net "H_CPU0_THERMTRIP_LVC1_R_N")
	)
	(segment
		(start 120.07088 -99.405948)
		(end 119.43588 -98.770948)
		(width 0.12954)
		(layer "F.Cu")
		(net "H_CPU0_THERMTRIP_LVC1_R_N")
	)
	(segment
		(start 120.3706 -94.615508)
		(end 119.85244 -94.097348)
		(width 0.12954)
		(layer "F.Cu")
		(net "H_CPU0_THERMTRIP_LVC1_R_N")
	)
	(via
		(at 120.07088 -99.405948)
		(size 0.508)
		(drill 0.254)
		(layers "F.Cu" "B.Cu")
		(net "H_CPU0_THERMTRIP_LVC1_R_N")
	)
	(via
		(at 356.400862 -266.128246)
		(size 0.4572)
		(drill 0.2032)
		(layers "F.Cu" "B.Cu")
		(net "H_CPU0_THERMTRIP_LVC1_R_N")
	)
	(via
		(at 326.370188 -263.769856)
		(size 0.6604)
		(drill 0.3302)
		(layers "F.Cu" "B.Cu")
		(net "H_CPU0_THERMTRIP_LVC1_R_N")
	)
	(via
		(at 123.571 -141.277848)
		(size 0.508)
		(drill 0.254)
		(layers "F.Cu" "B.Cu")
		(net "H_CPU0_THERMTRIP_LVC1_R_N")
	)
	(via
		(at 205.21803 -150.967948)
		(size 0.508)
		(drill 0.254)
		(layers "F.Cu" "B.Cu")
		(net "H_CPU0_THERMTRIP_LVC1_R_N")
	)
	(segment
		(start 303.379886 -264.211308)
		(end 302.39716 -264.211308)
		(width 0.12954)
		(layer "B.Cu")
		(net "H_CPU0_THERMTRIP_LVC1_R_N")
	)
	(segment
		(start 350.70161 -261.488174)
		(end 350.063054 -260.849618)
		(width 0.12954)
		(layer "B.Cu")
		(net "H_CPU0_THERMTRIP_LVC1_R_N")
	)
	(segment
		(start 294.02532 -201.097642)
		(end 291.714428 -198.78675)
		(width 0.12954)
		(layer "B.Cu")
		(net "H_CPU0_THERMTRIP_LVC1_R_N")
	)
	(segment
		(start 350.063054 -260.849618)
		(end 331.657452 -260.849618)
		(width 0.12954)
		(layer "B.Cu")
		(net "H_CPU0_THERMTRIP_LVC1_R_N")
	)
	(segment
		(start 302.39716 -264.211308)
		(end 301.6377 -263.451848)
		(width 0.12954)
		(layer "B.Cu")
		(net "H_CPU0_THERMTRIP_LVC1_R_N")
	)
	(segment
		(start 355.556566 -265.314176)
		(end 355.556566 -265.30427)
		(width 0.0889)
		(layer "B.Cu")
		(net "H_CPU0_THERMTRIP_LVC1_R_N")
	)
	(segment
		(start 355.096826 -264.767822)
		(end 355.060504 -264.7315)
		(width 0.0889)
		(layer "B.Cu")
		(net "H_CPU0_THERMTRIP_LVC1_R_N")
	)
	(segment
		(start 240.55578 -153.984198)
		(end 207.860646 -153.984198)
		(width 0.12954)
		(layer "B.Cu")
		(net "H_CPU0_THERMTRIP_LVC1_R_N")
	)
	(segment
		(start 307.41874 -264.856468)
		(end 307.362098 -264.91311)
		(width 0.12954)
		(layer "B.Cu")
		(net "H_CPU0_THERMTRIP_LVC1_R_N")
	)
	(segment
		(start 331.657452 -260.849618)
		(end 328.737214 -263.769856)
		(width 0.12954)
		(layer "B.Cu")
		(net "H_CPU0_THERMTRIP_LVC1_R_N")
	)
	(segment
		(start 326.370188 -263.769856)
		(end 322.869814 -263.769856)
		(width 0.12954)
		(layer "B.Cu")
		(net "H_CPU0_THERMTRIP_LVC1_R_N")
	)
	(segment
		(start 354.737162 -263.940544)
		(end 352.119946 -263.940544)
		(width 0.12954)
		(layer "B.Cu")
		(net "H_CPU0_THERMTRIP_LVC1_R_N")
	)
	(segment
		(start 356.400862 -266.128246)
		(end 356.395274 -266.129008)
		(width 0.0889)
		(layer "B.Cu")
		(net "H_CPU0_THERMTRIP_LVC1_R_N")
	)
	(segment
		(start 290.659058 -198.31431)
		(end 290.659058 -187.650374)
		(width 0.12954)
		(layer "B.Cu")
		(net "H_CPU0_THERMTRIP_LVC1_R_N")
	)
	(segment
		(start 291.714428 -198.78675)
		(end 291.131498 -198.78675)
		(width 0.12954)
		(layer "B.Cu")
		(net "H_CPU0_THERMTRIP_LVC1_R_N")
	)
	(segment
		(start 207.860646 -153.984198)
		(end 205.21803 -151.341582)
		(width 0.12954)
		(layer "B.Cu")
		(net "H_CPU0_THERMTRIP_LVC1_R_N")
	)
	(segment
		(start 328.737214 -263.769856)
		(end 326.370188 -263.769856)
		(width 0.12954)
		(layer "B.Cu")
		(net "H_CPU0_THERMTRIP_LVC1_R_N")
	)
	(segment
		(start 311.12968 -265.013948)
		(end 310.9722 -264.856468)
		(width 0.12954)
		(layer "B.Cu")
		(net "H_CPU0_THERMTRIP_LVC1_R_N")
	)
	(segment
		(start 290.659058 -187.650374)
		(end 289.785552 -186.776868)
		(width 0.12954)
		(layer "B.Cu")
		(net "H_CPU0_THERMTRIP_LVC1_R_N")
	)
	(segment
		(start 355.744526 -265.639042)
		(end 355.744018 -265.638534)
		(width 0.0889)
		(layer "B.Cu")
		(net "H_CPU0_THERMTRIP_LVC1_R_N")
	)
	(segment
		(start 307.362098 -264.91311)
		(end 304.081688 -264.91311)
		(width 0.12954)
		(layer "B.Cu")
		(net "H_CPU0_THERMTRIP_LVC1_R_N")
	)
	(segment
		(start 304.081688 -264.91311)
		(end 303.379886 -264.211308)
		(width 0.12954)
		(layer "B.Cu")
		(net "H_CPU0_THERMTRIP_LVC1_R_N")
	)
	(segment
		(start 301.6377 -262.867648)
		(end 301.18304 -262.412988)
		(width 0.12954)
		(layer "B.Cu")
		(net "H_CPU0_THERMTRIP_LVC1_R_N")
	)
	(segment
		(start 285.080202 -184.98947)
		(end 271.561306 -184.98947)
		(width 0.12954)
		(layer "B.Cu")
		(net "H_CPU0_THERMTRIP_LVC1_R_N")
	)
	(segment
		(start 286.8676 -186.776868)
		(end 285.080202 -184.98947)
		(width 0.12954)
		(layer "B.Cu")
		(net "H_CPU0_THERMTRIP_LVC1_R_N")
	)
	(segment
		(start 356.395274 -266.129008)
		(end 355.744526 -265.639042)
		(width 0.0889)
		(layer "B.Cu")
		(net "H_CPU0_THERMTRIP_LVC1_R_N")
	)
	(segment
		(start 271.561306 -184.98947)
		(end 269.540228 -182.968392)
		(width 0.12954)
		(layer "B.Cu")
		(net "H_CPU0_THERMTRIP_LVC1_R_N")
	)
	(segment
		(start 355.274118 -264.824718)
		(end 355.273864 -264.824718)
		(width 0.0889)
		(layer "B.Cu")
		(net "H_CPU0_THERMTRIP_LVC1_R_N")
	)
	(segment
		(start 301.18304 -258.082542)
		(end 299.122846 -256.022348)
		(width 0.12954)
		(layer "B.Cu")
		(net "H_CPU0_THERMTRIP_LVC1_R_N")
	)
	(segment
		(start 322.869814 -263.769856)
		(end 322.058792 -264.580878)
		(width 0.12954)
		(layer "B.Cu")
		(net "H_CPU0_THERMTRIP_LVC1_R_N")
	)
	(segment
		(start 355.060504 -264.7315)
		(end 355.060504 -264.263886)
		(width 0.0889)
		(layer "B.Cu")
		(net "H_CPU0_THERMTRIP_LVC1_R_N")
	)
	(segment
		(start 299.122846 -256.022348)
		(end 294.879014 -256.022348)
		(width 0.12954)
		(layer "B.Cu")
		(net "H_CPU0_THERMTRIP_LVC1_R_N")
	)
	(segment
		(start 355.060504 -264.263886)
		(end 354.737162 -263.940544)
		(width 0.0889)
		(layer "B.Cu")
		(net "H_CPU0_THERMTRIP_LVC1_R_N")
	)
	(segment
		(start 205.21803 -151.341582)
		(end 205.21803 -150.967948)
		(width 0.12954)
		(layer "B.Cu")
		(net "H_CPU0_THERMTRIP_LVC1_R_N")
	)
	(segment
		(start 294.02532 -255.168654)
		(end 294.02532 -201.097642)
		(width 0.12954)
		(layer "B.Cu")
		(net "H_CPU0_THERMTRIP_LVC1_R_N")
	)
	(segment
		(start 289.785552 -186.776868)
		(end 286.8676 -186.776868)
		(width 0.12954)
		(layer "B.Cu")
		(net "H_CPU0_THERMTRIP_LVC1_R_N")
	)
	(segment
		(start 355.744018 -265.638534)
		(end 355.735128 -265.633454)
		(width 0.0889)
		(layer "B.Cu")
		(net "H_CPU0_THERMTRIP_LVC1_R_N")
	)
	(segment
		(start 269.539974 -182.968392)
		(end 240.55578 -153.984198)
		(width 0.12954)
		(layer "B.Cu")
		(net "H_CPU0_THERMTRIP_LVC1_R_N")
	)
	(segment
		(start 291.131498 -198.78675)
		(end 290.659058 -198.31431)
		(width 0.12954)
		(layer "B.Cu")
		(net "H_CPU0_THERMTRIP_LVC1_R_N")
	)
	(segment
		(start 294.879014 -256.022348)
		(end 294.02532 -255.168654)
		(width 0.12954)
		(layer "B.Cu")
		(net "H_CPU0_THERMTRIP_LVC1_R_N")
	)
	(segment
		(start 350.70161 -262.522208)
		(end 350.70161 -261.488174)
		(width 0.12954)
		(layer "B.Cu")
		(net "H_CPU0_THERMTRIP_LVC1_R_N")
	)
	(segment
		(start 315.70295 -264.580878)
		(end 315.26988 -265.013948)
		(width 0.12954)
		(layer "B.Cu")
		(net "H_CPU0_THERMTRIP_LVC1_R_N")
	)
	(segment
		(start 301.6377 -263.451848)
		(end 301.6377 -262.867648)
		(width 0.12954)
		(layer "B.Cu")
		(net "H_CPU0_THERMTRIP_LVC1_R_N")
	)
	(segment
		(start 352.119946 -263.940544)
		(end 350.70161 -262.522208)
		(width 0.12954)
		(layer "B.Cu")
		(net "H_CPU0_THERMTRIP_LVC1_R_N")
	)
	(segment
		(start 310.9722 -264.856468)
		(end 307.41874 -264.856468)
		(width 0.12954)
		(layer "B.Cu")
		(net "H_CPU0_THERMTRIP_LVC1_R_N")
	)
	(segment
		(start 315.26988 -265.013948)
		(end 311.12968 -265.013948)
		(width 0.12954)
		(layer "B.Cu")
		(net "H_CPU0_THERMTRIP_LVC1_R_N")
	)
	(segment
		(start 322.058792 -264.580878)
		(end 315.70295 -264.580878)
		(width 0.12954)
		(layer "B.Cu")
		(net "H_CPU0_THERMTRIP_LVC1_R_N")
	)
	(segment
		(start 269.540228 -182.968392)
		(end 269.539974 -182.968392)
		(width 0.12954)
		(layer "B.Cu")
		(net "H_CPU0_THERMTRIP_LVC1_R_N")
	)
	(segment
		(start 301.18304 -262.412988)
		(end 301.18304 -258.082542)
		(width 0.12954)
		(layer "B.Cu")
		(net "H_CPU0_THERMTRIP_LVC1_R_N")
	)
	(arc
		(start 355.735128 -265.633454)
		(mid 355.604214 -265.497094)
		(end 355.556566 -265.314176)
		(width 0.0889)
		(layer "B.Cu")
		(net "H_CPU0_THERMTRIP_LVC1_R_N")
	)
	(arc
		(start 355.273864 -264.824718)
		(mid 355.187426 -264.789789)
		(end 355.096826 -264.767822)
		(width 0.0889)
		(layer "B.Cu")
		(net "H_CPU0_THERMTRIP_LVC1_R_N")
	)
	(arc
		(start 355.556566 -265.30427)
		(mid 355.478455 -265.027321)
		(end 355.274118 -264.824718)
		(width 0.0889)
		(layer "B.Cu")
		(net "H_CPU0_THERMTRIP_LVC1_R_N")
	)
	(segment
		(start 123.571 -141.277848)
		(end 122.35688 -140.063728)
		(width 0.127)
		(layer "In2.Cu")
		(net "H_CPU0_THERMTRIP_LVC1_R_N")
	)
	(segment
		(start 122.35688 -111.432848)
		(end 121.43994 -110.515908)
		(width 0.127)
		(layer "In2.Cu")
		(net "H_CPU0_THERMTRIP_LVC1_R_N")
	)
	(segment
		(start 119.99976 -103.281988)
		(end 119.99976 -99.477068)
		(width 0.127)
		(layer "In2.Cu")
		(net "H_CPU0_THERMTRIP_LVC1_R_N")
	)
	(segment
		(start 122.35688 -140.063728)
		(end 122.35688 -111.432848)
		(width 0.127)
		(layer "In2.Cu")
		(net "H_CPU0_THERMTRIP_LVC1_R_N")
	)
	(segment
		(start 121.43994 -104.722168)
		(end 119.99976 -103.281988)
		(width 0.127)
		(layer "In2.Cu")
		(net "H_CPU0_THERMTRIP_LVC1_R_N")
	)
	(segment
		(start 119.99976 -99.477068)
		(end 120.07088 -99.405948)
		(width 0.127)
		(layer "In2.Cu")
		(net "H_CPU0_THERMTRIP_LVC1_R_N")
	)
	(segment
		(start 121.43994 -110.515908)
		(end 121.43994 -104.722168)
		(width 0.127)
		(layer "In2.Cu")
		(net "H_CPU0_THERMTRIP_LVC1_R_N")
	)
	(segment
		(start 182.19928 -150.289768)
		(end 177.69586 -145.786348)
		(width 0.127)
		(layer "In13.Cu")
		(net "H_CPU0_THERMTRIP_LVC1_R_N")
	)
	(segment
		(start 185.58764 -152.535128)
		(end 183.34228 -150.289768)
		(width 0.127)
		(layer "In13.Cu")
		(net "H_CPU0_THERMTRIP_LVC1_R_N")
	)
	(segment
		(start 177.69586 -145.786348)
		(end 153.548842 -145.786348)
		(width 0.127)
		(layer "In13.Cu")
		(net "H_CPU0_THERMTRIP_LVC1_R_N")
	)
	(segment
		(start 191.41186 -159.502348)
		(end 185.58764 -153.678128)
		(width 0.127)
		(layer "In13.Cu")
		(net "H_CPU0_THERMTRIP_LVC1_R_N")
	)
	(segment
		(start 185.58764 -153.678128)
		(end 185.58764 -152.535128)
		(width 0.127)
		(layer "In13.Cu")
		(net "H_CPU0_THERMTRIP_LVC1_R_N")
	)
	(segment
		(start 205.01991 -150.967948)
		(end 196.48551 -159.502348)
		(width 0.127)
		(layer "In13.Cu")
		(net "H_CPU0_THERMTRIP_LVC1_R_N")
	)
	(segment
		(start 205.21803 -150.967948)
		(end 205.01991 -150.967948)
		(width 0.127)
		(layer "In13.Cu")
		(net "H_CPU0_THERMTRIP_LVC1_R_N")
	)
	(segment
		(start 196.48551 -159.502348)
		(end 191.41186 -159.502348)
		(width 0.127)
		(layer "In13.Cu")
		(net "H_CPU0_THERMTRIP_LVC1_R_N")
	)
	(segment
		(start 149.319742 -141.557248)
		(end 123.8504 -141.557248)
		(width 0.127)
		(layer "In13.Cu")
		(net "H_CPU0_THERMTRIP_LVC1_R_N")
	)
	(segment
		(start 123.8504 -141.557248)
		(end 123.571 -141.277848)
		(width 0.127)
		(layer "In13.Cu")
		(net "H_CPU0_THERMTRIP_LVC1_R_N")
	)
	(segment
		(start 153.548842 -145.786348)
		(end 149.319742 -141.557248)
		(width 0.127)
		(layer "In13.Cu")
		(net "H_CPU0_THERMTRIP_LVC1_R_N")
	)
	(segment
		(start 183.34228 -150.289768)
		(end 182.19928 -150.289768)
		(width 0.127)
		(layer "In13.Cu")
		(net "H_CPU0_THERMTRIP_LVC1_R_N")
	)
	(segment
		(start 123.62688 -92.274898)
		(end 123.62688 -91.658948)
		(width 0.12954)
		(layer "F.Cu")
		(net "H_CPU0_THERMTRIP_LVC1_N")
	)
	(segment
		(start 182.155592 -105.775506)
		(end 182.555642 -105.375456)
		(width 0.12954)
		(layer "F.Cu")
		(net "H_CPU0_THERMTRIP_LVC1_N")
	)
	(via
		(at 182.555642 -105.375456)
		(size 0.4572)
		(drill 0.254)
		(layers "F.Cu" "B.Cu")
		(net "H_CPU0_THERMTRIP_LVC1_N")
	)
	(via
		(at 123.62688 -91.658948)
		(size 0.508)
		(drill 0.254)
		(layers "F.Cu" "B.Cu")
		(net "H_CPU0_THERMTRIP_LVC1_N")
	)
	(segment
		(start 141.957552 -85.090508)
		(end 143.484346 -85.090508)
		(width 0.127)
		(layer "In15.Cu")
		(net "H_CPU0_THERMTRIP_LVC1_N")
	)
	(segment
		(start 181.80812 -98.420428)
		(end 181.80812 -99.827588)
		(width 0.127)
		(layer "In15.Cu")
		(net "H_CPU0_THERMTRIP_LVC1_N")
	)
	(segment
		(start 123.62688 -91.658948)
		(end 123.62688 -90.62212)
		(width 0.127)
		(layer "In15.Cu")
		(net "H_CPU0_THERMTRIP_LVC1_N")
	)
	(segment
		(start 150.9903 -92.596462)
		(end 150.9903 -93.411802)
		(width 0.127)
		(layer "In15.Cu")
		(net "H_CPU0_THERMTRIP_LVC1_N")
	)
	(segment
		(start 157.49397 -96.135952)
		(end 158.732474 -94.897448)
		(width 0.127)
		(layer "In15.Cu")
		(net "H_CPU0_THERMTRIP_LVC1_N")
	)
	(segment
		(start 177.1523 -94.897448)
		(end 177.3428 -95.087948)
		(width 0.127)
		(layer "In15.Cu")
		(net "H_CPU0_THERMTRIP_LVC1_N")
	)
	(segment
		(start 123.62688 -90.62212)
		(end 127.2794 -86.9696)
		(width 0.127)
		(layer "In15.Cu")
		(net "H_CPU0_THERMTRIP_LVC1_N")
	)
	(segment
		(start 127.2794 -85.120988)
		(end 129.21742 -83.182968)
		(width 0.127)
		(layer "In15.Cu")
		(net "H_CPU0_THERMTRIP_LVC1_N")
	)
	(segment
		(start 127.2794 -86.9696)
		(end 127.2794 -85.120988)
		(width 0.127)
		(layer "In15.Cu")
		(net "H_CPU0_THERMTRIP_LVC1_N")
	)
	(segment
		(start 153.71445 -96.135952)
		(end 157.49397 -96.135952)
		(width 0.127)
		(layer "In15.Cu")
		(net "H_CPU0_THERMTRIP_LVC1_N")
	)
	(segment
		(start 181.80812 -99.827588)
		(end 182.70982 -100.729288)
		(width 0.127)
		(layer "In15.Cu")
		(net "H_CPU0_THERMTRIP_LVC1_N")
	)
	(segment
		(start 143.484346 -85.090508)
		(end 150.9903 -92.596462)
		(width 0.127)
		(layer "In15.Cu")
		(net "H_CPU0_THERMTRIP_LVC1_N")
	)
	(segment
		(start 158.732474 -94.897448)
		(end 177.1523 -94.897448)
		(width 0.127)
		(layer "In15.Cu")
		(net "H_CPU0_THERMTRIP_LVC1_N")
	)
	(segment
		(start 177.3428 -95.537528)
		(end 178.87442 -97.069148)
		(width 0.127)
		(layer "In15.Cu")
		(net "H_CPU0_THERMTRIP_LVC1_N")
	)
	(segment
		(start 140.050012 -83.182968)
		(end 141.957552 -85.090508)
		(width 0.127)
		(layer "In15.Cu")
		(net "H_CPU0_THERMTRIP_LVC1_N")
	)
	(segment
		(start 178.87442 -97.069148)
		(end 180.45684 -97.069148)
		(width 0.127)
		(layer "In15.Cu")
		(net "H_CPU0_THERMTRIP_LVC1_N")
	)
	(segment
		(start 182.70982 -105.221278)
		(end 182.555642 -105.375456)
		(width 0.127)
		(layer "In15.Cu")
		(net "H_CPU0_THERMTRIP_LVC1_N")
	)
	(segment
		(start 182.70982 -100.729288)
		(end 182.70982 -105.221278)
		(width 0.127)
		(layer "In15.Cu")
		(net "H_CPU0_THERMTRIP_LVC1_N")
	)
	(segment
		(start 177.3428 -95.087948)
		(end 177.3428 -95.537528)
		(width 0.127)
		(layer "In15.Cu")
		(net "H_CPU0_THERMTRIP_LVC1_N")
	)
	(segment
		(start 129.21742 -83.182968)
		(end 140.050012 -83.182968)
		(width 0.127)
		(layer "In15.Cu")
		(net "H_CPU0_THERMTRIP_LVC1_N")
	)
	(segment
		(start 180.45684 -97.069148)
		(end 181.80812 -98.420428)
		(width 0.127)
		(layer "In15.Cu")
		(net "H_CPU0_THERMTRIP_LVC1_N")
	)
	(segment
		(start 150.9903 -93.411802)
		(end 153.71445 -96.135952)
		(width 0.127)
		(layer "In15.Cu")
		(net "H_CPU0_THERMTRIP_LVC1_N")
	)
	(segment
		(start 354.881434 -231.436164)
		(end 354.881434 -230.900478)
		(width 0.12954)
		(layer "F.Cu")
		(net "H_CPU0_RMCA_LVC1_R_N")
	)
	(segment
		(start 354.88118 -231.436418)
		(end 354.881434 -231.436164)
		(width 0.12954)
		(layer "F.Cu")
		(net "H_CPU0_RMCA_LVC1_R_N")
	)
	(via
		(at 326.470264 -219.783914)
		(size 0.6604)
		(drill 0.3302)
		(layers "F.Cu" "B.Cu")
		(net "H_CPU0_RMCA_LVC1_R_N")
	)
	(via
		(at 354.881434 -230.900478)
		(size 0.4572)
		(drill 0.2032)
		(layers "F.Cu" "B.Cu")
		(net "H_CPU0_RMCA_LVC1_R_N")
	)
	(segment
		(start 350.941132 -226.345242)
		(end 350.926146 -226.336606)
		(width 0.0889)
		(layer "B.Cu")
		(net "H_CPU0_RMCA_LVC1_R_N")
	)
	(segment
		(start 326.470264 -219.783914)
		(end 324.527418 -217.841068)
		(width 0.12954)
		(layer "B.Cu")
		(net "H_CPU0_RMCA_LVC1_R_N")
	)
	(segment
		(start 323.751702 -188.88456)
		(end 323.661278 -188.88456)
		(width 0.12954)
		(layer "B.Cu")
		(net "H_CPU0_RMCA_LVC1_R_N")
	)
	(segment
		(start 353.203764 -229.588568)
		(end 353.189032 -229.597204)
		(width 0.0889)
		(layer "B.Cu")
		(net "H_CPU0_RMCA_LVC1_R_N")
	)
	(segment
		(start 332.114652 -224.310956)
		(end 331.664056 -223.86036)
		(width 0.12954)
		(layer "B.Cu")
		(net "H_CPU0_RMCA_LVC1_R_N")
	)
	(segment
		(start 344.826082 -225.527616)
		(end 344.81135 -225.51898)
		(width 0.0889)
		(layer "B.Cu")
		(net "H_CPU0_RMCA_LVC1_R_N")
	)
	(segment
		(start 351.874836 -227.969318)
		(end 351.865946 -227.964238)
		(width 0.0889)
		(layer "B.Cu")
		(net "H_CPU0_RMCA_LVC1_R_N")
	)
	(segment
		(start 346.705682 -225.527616)
		(end 346.69095 -225.51898)
		(width 0.0889)
		(layer "B.Cu")
		(net "H_CPU0_RMCA_LVC1_R_N")
	)
	(segment
		(start 337.307682 -225.527616)
		(end 337.297268 -225.52152)
		(width 0.0889)
		(layer "B.Cu")
		(net "H_CPU0_RMCA_LVC1_R_N")
	)
	(segment
		(start 342.946482 -225.527616)
		(end 342.93175 -225.51898)
		(width 0.0889)
		(layer "B.Cu")
		(net "H_CPU0_RMCA_LVC1_R_N")
	)
	(segment
		(start 351.404936 -227.155502)
		(end 351.396046 -227.150422)
		(width 0.0889)
		(layer "B.Cu")
		(net "H_CPU0_RMCA_LVC1_R_N")
	)
	(segment
		(start 340.127082 -225.527616)
		(end 340.11235 -225.51898)
		(width 0.0889)
		(layer "B.Cu")
		(net "H_CPU0_RMCA_LVC1_R_N")
	)
	(segment
		(start 343.886282 -225.527616)
		(end 343.87155 -225.51898)
		(width 0.0889)
		(layer "B.Cu")
		(net "H_CPU0_RMCA_LVC1_R_N")
	)
	(segment
		(start 350.747584 -226.017328)
		(end 350.747584 -226.003104)
		(width 0.0889)
		(layer "B.Cu")
		(net "H_CPU0_RMCA_LVC1_R_N")
	)
	(segment
		(start 332.441804 -224.638108)
		(end 332.114652 -224.310956)
		(width 0.0889)
		(layer "B.Cu")
		(net "H_CPU0_RMCA_LVC1_R_N")
	)
	(segment
		(start 354.881434 -230.900478)
		(end 354.372164 -230.534464)
		(width 0.0889)
		(layer "B.Cu")
		(net "H_CPU0_RMCA_LVC1_R_N")
	)
	(segment
		(start 336.368136 -225.527616)
		(end 336.359246 -225.522536)
		(width 0.0889)
		(layer "B.Cu")
		(net "H_CPU0_RMCA_LVC1_R_N")
	)
	(segment
		(start 351.687384 -227.64496)
		(end 351.687384 -227.635054)
		(width 0.0889)
		(layer "B.Cu")
		(net "H_CPU0_RMCA_LVC1_R_N")
	)
	(segment
		(start 352.350578 -228.786944)
		(end 352.335592 -228.778308)
		(width 0.0889)
		(layer "B.Cu")
		(net "H_CPU0_RMCA_LVC1_R_N")
	)
	(segment
		(start 348.585282 -225.527616)
		(end 348.57055 -225.51898)
		(width 0.0889)
		(layer "B.Cu")
		(net "H_CPU0_RMCA_LVC1_R_N")
	)
	(segment
		(start 324.527418 -189.660276)
		(end 323.751702 -188.88456)
		(width 0.12954)
		(layer "B.Cu")
		(net "H_CPU0_RMCA_LVC1_R_N")
	)
	(segment
		(start 342.006682 -225.527616)
		(end 341.99195 -225.51898)
		(width 0.0889)
		(layer "B.Cu")
		(net "H_CPU0_RMCA_LVC1_R_N")
	)
	(segment
		(start 334.018636 -224.7138)
		(end 334.008222 -224.707704)
		(width 0.0889)
		(layer "B.Cu")
		(net "H_CPU0_RMCA_LVC1_R_N")
	)
	(segment
		(start 345.765882 -225.527616)
		(end 345.75115 -225.51898)
		(width 0.0889)
		(layer "B.Cu")
		(net "H_CPU0_RMCA_LVC1_R_N")
	)
	(segment
		(start 331.664056 -223.86036)
		(end 330.54671 -223.86036)
		(width 0.12954)
		(layer "B.Cu")
		(net "H_CPU0_RMCA_LVC1_R_N")
	)
	(segment
		(start 336.180684 -225.203258)
		(end 336.180684 -225.193352)
		(width 0.0889)
		(layer "B.Cu")
		(net "H_CPU0_RMCA_LVC1_R_N")
	)
	(segment
		(start 347.645482 -225.527616)
		(end 347.63075 -225.51898)
		(width 0.0889)
		(layer "B.Cu")
		(net "H_CPU0_RMCA_LVC1_R_N")
	)
	(segment
		(start 349.525082 -225.527616)
		(end 349.51035 -225.51898)
		(width 0.0889)
		(layer "B.Cu")
		(net "H_CPU0_RMCA_LVC1_R_N")
	)
	(segment
		(start 332.796134 -224.638108)
		(end 332.441804 -224.638108)
		(width 0.0889)
		(layer "B.Cu")
		(net "H_CPU0_RMCA_LVC1_R_N")
	)
	(segment
		(start 341.066882 -225.527616)
		(end 341.05215 -225.51898)
		(width 0.0889)
		(layer "B.Cu")
		(net "H_CPU0_RMCA_LVC1_R_N")
	)
	(segment
		(start 330.54671 -223.86036)
		(end 326.470264 -219.783914)
		(width 0.12954)
		(layer "B.Cu")
		(net "H_CPU0_RMCA_LVC1_R_N")
	)
	(segment
		(start 354.224336 -230.41102)
		(end 354.215446 -230.40594)
		(width 0.0889)
		(layer "B.Cu")
		(net "H_CPU0_RMCA_LVC1_R_N")
	)
	(segment
		(start 324.527418 -217.841068)
		(end 324.527418 -189.660276)
		(width 0.12954)
		(layer "B.Cu")
		(net "H_CPU0_RMCA_LVC1_R_N")
	)
	(segment
		(start 352.15703 -228.45903)
		(end 352.15703 -228.436932)
		(width 0.0889)
		(layer "B.Cu")
		(net "H_CPU0_RMCA_LVC1_R_N")
	)
	(segment
		(start 338.247482 -225.527616)
		(end 338.23275 -225.51898)
		(width 0.0889)
		(layer "B.Cu")
		(net "H_CPU0_RMCA_LVC1_R_N")
	)
	(arc
		(start 336.180684 -225.193352)
		(mid 336.102573 -224.916403)
		(end 335.898236 -224.7138)
		(width 0.0889)
		(layer "B.Cu")
		(net "H_CPU0_RMCA_LVC1_R_N")
	)
	(arc
		(start 342.93175 -225.51898)
		(mid 342.655309 -225.451814)
		(end 342.381078 -225.527616)
		(width 0.0889)
		(layer "B.Cu")
		(net "H_CPU0_RMCA_LVC1_R_N")
	)
	(arc
		(start 338.621878 -225.527616)
		(mid 338.43468 -225.577759)
		(end 338.247482 -225.527616)
		(width 0.0889)
		(layer "B.Cu")
		(net "H_CPU0_RMCA_LVC1_R_N")
	)
	(arc
		(start 354.372164 -230.534464)
		(mid 354.30354 -230.466409)
		(end 354.224336 -230.41102)
		(width 0.0889)
		(layer "B.Cu")
		(net "H_CPU0_RMCA_LVC1_R_N")
	)
	(arc
		(start 342.381078 -225.527616)
		(mid 342.19388 -225.577759)
		(end 342.006682 -225.527616)
		(width 0.0889)
		(layer "B.Cu")
		(net "H_CPU0_RMCA_LVC1_R_N")
	)
	(arc
		(start 334.393032 -224.7138)
		(mid 334.205834 -224.763943)
		(end 334.018636 -224.7138)
		(width 0.0889)
		(layer "B.Cu")
		(net "H_CPU0_RMCA_LVC1_R_N")
	)
	(arc
		(start 352.335592 -228.778308)
		(mid 352.204678 -228.641948)
		(end 352.15703 -228.45903)
		(width 0.0889)
		(layer "B.Cu")
		(net "H_CPU0_RMCA_LVC1_R_N")
	)
	(arc
		(start 344.81135 -225.51898)
		(mid 344.534909 -225.451814)
		(end 344.260678 -225.527616)
		(width 0.0889)
		(layer "B.Cu")
		(net "H_CPU0_RMCA_LVC1_R_N")
	)
	(arc
		(start 333.452978 -224.7138)
		(mid 333.26578 -224.763943)
		(end 333.078582 -224.7138)
		(width 0.0889)
		(layer "B.Cu")
		(net "H_CPU0_RMCA_LVC1_R_N")
	)
	(arc
		(start 351.687384 -227.635054)
		(mid 351.609273 -227.358105)
		(end 351.404936 -227.155502)
		(width 0.0889)
		(layer "B.Cu")
		(net "H_CPU0_RMCA_LVC1_R_N")
	)
	(arc
		(start 354.215446 -230.40594)
		(mid 354.084532 -230.26958)
		(end 354.036884 -230.086662)
		(width 0.0889)
		(layer "B.Cu")
		(net "H_CPU0_RMCA_LVC1_R_N")
	)
	(arc
		(start 348.959678 -225.527616)
		(mid 348.77248 -225.577759)
		(end 348.585282 -225.527616)
		(width 0.0889)
		(layer "B.Cu")
		(net "H_CPU0_RMCA_LVC1_R_N")
	)
	(arc
		(start 337.682078 -225.527616)
		(mid 337.49488 -225.577759)
		(end 337.307682 -225.527616)
		(width 0.0889)
		(layer "B.Cu")
		(net "H_CPU0_RMCA_LVC1_R_N")
	)
	(arc
		(start 349.51035 -225.51898)
		(mid 349.233909 -225.451814)
		(end 348.959678 -225.527616)
		(width 0.0889)
		(layer "B.Cu")
		(net "H_CPU0_RMCA_LVC1_R_N")
	)
	(arc
		(start 343.87155 -225.51898)
		(mid 343.595109 -225.451814)
		(end 343.320878 -225.527616)
		(width 0.0889)
		(layer "B.Cu")
		(net "H_CPU0_RMCA_LVC1_R_N")
	)
	(arc
		(start 348.57055 -225.51898)
		(mid 348.294109 -225.451814)
		(end 348.019878 -225.527616)
		(width 0.0889)
		(layer "B.Cu")
		(net "H_CPU0_RMCA_LVC1_R_N")
	)
	(arc
		(start 335.332832 -224.7138)
		(mid 335.145634 -224.763943)
		(end 334.958436 -224.7138)
		(width 0.0889)
		(layer "B.Cu")
		(net "H_CPU0_RMCA_LVC1_R_N")
	)
	(arc
		(start 346.140278 -225.527616)
		(mid 345.95308 -225.577759)
		(end 345.765882 -225.527616)
		(width 0.0889)
		(layer "B.Cu")
		(net "H_CPU0_RMCA_LVC1_R_N")
	)
	(arc
		(start 343.320878 -225.527616)
		(mid 343.13368 -225.577759)
		(end 342.946482 -225.527616)
		(width 0.0889)
		(layer "B.Cu")
		(net "H_CPU0_RMCA_LVC1_R_N")
	)
	(arc
		(start 338.23275 -225.51898)
		(mid 337.956309 -225.451814)
		(end 337.682078 -225.527616)
		(width 0.0889)
		(layer "B.Cu")
		(net "H_CPU0_RMCA_LVC1_R_N")
	)
	(arc
		(start 341.441278 -225.527616)
		(mid 341.25408 -225.577759)
		(end 341.066882 -225.527616)
		(width 0.0889)
		(layer "B.Cu")
		(net "H_CPU0_RMCA_LVC1_R_N")
	)
	(arc
		(start 340.11235 -225.51898)
		(mid 339.835909 -225.451814)
		(end 339.561678 -225.527616)
		(width 0.0889)
		(layer "B.Cu")
		(net "H_CPU0_RMCA_LVC1_R_N")
	)
	(arc
		(start 335.898236 -224.7138)
		(mid 335.615534 -224.638024)
		(end 335.332832 -224.7138)
		(width 0.0889)
		(layer "B.Cu")
		(net "H_CPU0_RMCA_LVC1_R_N")
	)
	(arc
		(start 339.561678 -225.527616)
		(mid 339.37448 -225.577759)
		(end 339.187282 -225.527616)
		(width 0.0889)
		(layer "B.Cu")
		(net "H_CPU0_RMCA_LVC1_R_N")
	)
	(arc
		(start 354.036884 -230.086662)
		(mid 353.761596 -229.601364)
		(end 353.203764 -229.588568)
		(width 0.0889)
		(layer "B.Cu")
		(net "H_CPU0_RMCA_LVC1_R_N")
	)
	(arc
		(start 350.747584 -226.003104)
		(mid 350.458802 -225.524008)
		(end 349.899478 -225.527616)
		(width 0.0889)
		(layer "B.Cu")
		(net "H_CPU0_RMCA_LVC1_R_N")
	)
	(arc
		(start 352.627184 -229.272846)
		(mid 352.553193 -228.99328)
		(end 352.350578 -228.786944)
		(width 0.0889)
		(layer "B.Cu")
		(net "H_CPU0_RMCA_LVC1_R_N")
	)
	(arc
		(start 337.297268 -225.52152)
		(mid 337.01909 -225.451828)
		(end 336.742532 -225.527616)
		(width 0.0889)
		(layer "B.Cu")
		(net "H_CPU0_RMCA_LVC1_R_N")
	)
	(arc
		(start 336.359246 -225.522536)
		(mid 336.228332 -225.386176)
		(end 336.180684 -225.203258)
		(width 0.0889)
		(layer "B.Cu")
		(net "H_CPU0_RMCA_LVC1_R_N")
	)
	(arc
		(start 334.008222 -224.707704)
		(mid 333.72979 -224.637858)
		(end 333.452978 -224.7138)
		(width 0.0889)
		(layer "B.Cu")
		(net "H_CPU0_RMCA_LVC1_R_N")
	)
	(arc
		(start 351.396046 -227.150422)
		(mid 351.265132 -227.014062)
		(end 351.217484 -226.831144)
		(width 0.0889)
		(layer "B.Cu")
		(net "H_CPU0_RMCA_LVC1_R_N")
	)
	(arc
		(start 341.99195 -225.51898)
		(mid 341.715509 -225.451814)
		(end 341.441278 -225.527616)
		(width 0.0889)
		(layer "B.Cu")
		(net "H_CPU0_RMCA_LVC1_R_N")
	)
	(arc
		(start 351.217484 -226.831144)
		(mid 351.143568 -226.551642)
		(end 350.941132 -226.345242)
		(width 0.0889)
		(layer "B.Cu")
		(net "H_CPU0_RMCA_LVC1_R_N")
	)
	(arc
		(start 346.69095 -225.51898)
		(mid 346.414509 -225.451814)
		(end 346.140278 -225.527616)
		(width 0.0889)
		(layer "B.Cu")
		(net "H_CPU0_RMCA_LVC1_R_N")
	)
	(arc
		(start 349.899478 -225.527616)
		(mid 349.71228 -225.577759)
		(end 349.525082 -225.527616)
		(width 0.0889)
		(layer "B.Cu")
		(net "H_CPU0_RMCA_LVC1_R_N")
	)
	(arc
		(start 348.019878 -225.527616)
		(mid 347.83268 -225.577759)
		(end 347.645482 -225.527616)
		(width 0.0889)
		(layer "B.Cu")
		(net "H_CPU0_RMCA_LVC1_R_N")
	)
	(arc
		(start 345.75115 -225.51898)
		(mid 345.474709 -225.451814)
		(end 345.200478 -225.527616)
		(width 0.0889)
		(layer "B.Cu")
		(net "H_CPU0_RMCA_LVC1_R_N")
	)
	(arc
		(start 345.200478 -225.527616)
		(mid 345.01328 -225.577759)
		(end 344.826082 -225.527616)
		(width 0.0889)
		(layer "B.Cu")
		(net "H_CPU0_RMCA_LVC1_R_N")
	)
	(arc
		(start 347.63075 -225.51898)
		(mid 347.354309 -225.451814)
		(end 347.080078 -225.527616)
		(width 0.0889)
		(layer "B.Cu")
		(net "H_CPU0_RMCA_LVC1_R_N")
	)
	(arc
		(start 333.078582 -224.7138)
		(mid 332.94234 -224.657366)
		(end 332.796134 -224.638108)
		(width 0.0889)
		(layer "B.Cu")
		(net "H_CPU0_RMCA_LVC1_R_N")
	)
	(arc
		(start 334.958436 -224.7138)
		(mid 334.675734 -224.638024)
		(end 334.393032 -224.7138)
		(width 0.0889)
		(layer "B.Cu")
		(net "H_CPU0_RMCA_LVC1_R_N")
	)
	(arc
		(start 336.742532 -225.527616)
		(mid 336.555334 -225.577759)
		(end 336.368136 -225.527616)
		(width 0.0889)
		(layer "B.Cu")
		(net "H_CPU0_RMCA_LVC1_R_N")
	)
	(arc
		(start 352.15703 -228.436932)
		(mid 352.076119 -228.166804)
		(end 351.874836 -227.969318)
		(width 0.0889)
		(layer "B.Cu")
		(net "H_CPU0_RMCA_LVC1_R_N")
	)
	(arc
		(start 350.926146 -226.336606)
		(mid 350.795232 -226.200246)
		(end 350.747584 -226.017328)
		(width 0.0889)
		(layer "B.Cu")
		(net "H_CPU0_RMCA_LVC1_R_N")
	)
	(arc
		(start 341.05215 -225.51898)
		(mid 340.775709 -225.451814)
		(end 340.501478 -225.527616)
		(width 0.0889)
		(layer "B.Cu")
		(net "H_CPU0_RMCA_LVC1_R_N")
	)
	(arc
		(start 351.865946 -227.964238)
		(mid 351.735032 -227.827878)
		(end 351.687384 -227.64496)
		(width 0.0889)
		(layer "B.Cu")
		(net "H_CPU0_RMCA_LVC1_R_N")
	)
	(arc
		(start 339.187282 -225.527616)
		(mid 338.90458 -225.451874)
		(end 338.621878 -225.527616)
		(width 0.0889)
		(layer "B.Cu")
		(net "H_CPU0_RMCA_LVC1_R_N")
	)
	(arc
		(start 340.501478 -225.527616)
		(mid 340.31428 -225.577759)
		(end 340.127082 -225.527616)
		(width 0.0889)
		(layer "B.Cu")
		(net "H_CPU0_RMCA_LVC1_R_N")
	)
	(arc
		(start 344.260678 -225.527616)
		(mid 344.07348 -225.577759)
		(end 343.886282 -225.527616)
		(width 0.0889)
		(layer "B.Cu")
		(net "H_CPU0_RMCA_LVC1_R_N")
	)
	(arc
		(start 353.189032 -229.597204)
		(mid 352.814557 -229.597158)
		(end 352.627184 -229.272846)
		(width 0.0889)
		(layer "B.Cu")
		(net "H_CPU0_RMCA_LVC1_R_N")
	)
	(arc
		(start 347.080078 -225.527616)
		(mid 346.89288 -225.577759)
		(end 346.705682 -225.527616)
		(width 0.0889)
		(layer "B.Cu")
		(net "H_CPU0_RMCA_LVC1_R_N")
	)
	(segment
		(start 184.555638 -107.375452)
		(end 184.955688 -106.975402)
		(width 0.12954)
		(layer "F.Cu")
		(net "H_CPU0_PROCHOT_LVC1_R_N")
	)
	(via
		(at 255.45288 -126.710948)
		(size 0.508)
		(drill 0.254)
		(layers "F.Cu" "B.Cu")
		(net "H_CPU0_PROCHOT_LVC1_R_N")
	)
	(via
		(at 260.135116 -152.692608)
		(size 0.508)
		(drill 0.254)
		(layers "F.Cu" "B.Cu")
		(net "H_CPU0_PROCHOT_LVC1_R_N")
	)
	(via
		(at 184.955688 -106.975402)
		(size 0.4572)
		(drill 0.254)
		(layers "F.Cu" "B.Cu")
		(net "H_CPU0_PROCHOT_LVC1_R_N")
	)
	(segment
		(start 305.858418 -173.61789)
		(end 318.223138 -185.98261)
		(width 0.12954)
		(layer "B.Cu")
		(net "H_CPU0_PROCHOT_LVC1_R_N")
	)
	(segment
		(start 260.135116 -152.692608)
		(end 260.135116 -157.994096)
		(width 0.12954)
		(layer "B.Cu")
		(net "H_CPU0_PROCHOT_LVC1_R_N")
	)
	(segment
		(start 318.223138 -185.98261)
		(end 318.223138 -187.50788)
		(width 0.12954)
		(layer "B.Cu")
		(net "H_CPU0_PROCHOT_LVC1_R_N")
	)
	(segment
		(start 260.135116 -157.994096)
		(end 275.75891 -173.61789)
		(width 0.12954)
		(layer "B.Cu")
		(net "H_CPU0_PROCHOT_LVC1_R_N")
	)
	(segment
		(start 275.75891 -173.61789)
		(end 305.858418 -173.61789)
		(width 0.12954)
		(layer "B.Cu")
		(net "H_CPU0_PROCHOT_LVC1_R_N")
	)
	(segment
		(start 257.48488 -151.348948)
		(end 257.48488 -128.742948)
		(width 0.127)
		(layer "In2.Cu")
		(net "H_CPU0_PROCHOT_LVC1_R_N")
	)
	(segment
		(start 259.299456 -151.856948)
		(end 257.99288 -151.856948)
		(width 0.127)
		(layer "In2.Cu")
		(net "H_CPU0_PROCHOT_LVC1_R_N")
	)
	(segment
		(start 260.135116 -152.692608)
		(end 259.299456 -151.856948)
		(width 0.127)
		(layer "In2.Cu")
		(net "H_CPU0_PROCHOT_LVC1_R_N")
	)
	(segment
		(start 257.48488 -128.742948)
		(end 255.45288 -126.710948)
		(width 0.127)
		(layer "In2.Cu")
		(net "H_CPU0_PROCHOT_LVC1_R_N")
	)
	(segment
		(start 257.99288 -151.856948)
		(end 257.48488 -151.348948)
		(width 0.127)
		(layer "In2.Cu")
		(net "H_CPU0_PROCHOT_LVC1_R_N")
	)
	(segment
		(start 240.035842 -113.971832)
		(end 224.046796 -113.971832)
		(width 0.127)
		(layer "In6.Cu")
		(net "H_CPU0_PROCHOT_LVC1_R_N")
	)
	(segment
		(start 191.52616 -111.9251)
		(end 187.75426 -111.9251)
		(width 0.127)
		(layer "In6.Cu")
		(net "H_CPU0_PROCHOT_LVC1_R_N")
	)
	(segment
		(start 187.75426 -111.9251)
		(end 187.499752 -112.179608)
		(width 0.127)
		(layer "In6.Cu")
		(net "H_CPU0_PROCHOT_LVC1_R_N")
	)
	(segment
		(start 187.499752 -112.179608)
		(end 181.56682 -112.179608)
		(width 0.127)
		(layer "In6.Cu")
		(net "H_CPU0_PROCHOT_LVC1_R_N")
	)
	(segment
		(start 198.32066 -110.78972)
		(end 192.66154 -110.78972)
		(width 0.127)
		(layer "In6.Cu")
		(net "H_CPU0_PROCHOT_LVC1_R_N")
	)
	(segment
		(start 198.82104 -113.02746)
		(end 198.82104 -111.2901)
		(width 0.127)
		(layer "In6.Cu")
		(net "H_CPU0_PROCHOT_LVC1_R_N")
	)
	(segment
		(start 220.68282 -117.335808)
		(end 210.481418 -117.335808)
		(width 0.127)
		(layer "In6.Cu")
		(net "H_CPU0_PROCHOT_LVC1_R_N")
	)
	(segment
		(start 255.32588 -124.961396)
		(end 248.376694 -118.01221)
		(width 0.127)
		(layer "In6.Cu")
		(net "H_CPU0_PROCHOT_LVC1_R_N")
	)
	(segment
		(start 210.024218 -116.878608)
		(end 209.38109 -116.878608)
		(width 0.127)
		(layer "In6.Cu")
		(net "H_CPU0_PROCHOT_LVC1_R_N")
	)
	(segment
		(start 181.56682 -112.179608)
		(end 181.356 -111.968788)
		(width 0.127)
		(layer "In6.Cu")
		(net "H_CPU0_PROCHOT_LVC1_R_N")
	)
	(segment
		(start 181.56682 -106.573828)
		(end 184.554114 -106.573828)
		(width 0.127)
		(layer "In6.Cu")
		(net "H_CPU0_PROCHOT_LVC1_R_N")
	)
	(segment
		(start 255.32588 -126.583948)
		(end 255.32588 -124.961396)
		(width 0.127)
		(layer "In6.Cu")
		(net "H_CPU0_PROCHOT_LVC1_R_N")
	)
	(segment
		(start 198.82104 -111.2901)
		(end 198.32066 -110.78972)
		(width 0.127)
		(layer "In6.Cu")
		(net "H_CPU0_PROCHOT_LVC1_R_N")
	)
	(segment
		(start 184.554114 -106.573828)
		(end 184.955688 -106.975402)
		(width 0.127)
		(layer "In6.Cu")
		(net "H_CPU0_PROCHOT_LVC1_R_N")
	)
	(segment
		(start 224.046796 -113.971832)
		(end 220.68282 -117.335808)
		(width 0.127)
		(layer "In6.Cu")
		(net "H_CPU0_PROCHOT_LVC1_R_N")
	)
	(segment
		(start 206.162402 -113.65992)
		(end 199.4535 -113.65992)
		(width 0.127)
		(layer "In6.Cu")
		(net "H_CPU0_PROCHOT_LVC1_R_N")
	)
	(segment
		(start 192.66154 -110.78972)
		(end 191.52616 -111.9251)
		(width 0.127)
		(layer "In6.Cu")
		(net "H_CPU0_PROCHOT_LVC1_R_N")
	)
	(segment
		(start 209.38109 -116.878608)
		(end 206.162402 -113.65992)
		(width 0.127)
		(layer "In6.Cu")
		(net "H_CPU0_PROCHOT_LVC1_R_N")
	)
	(segment
		(start 181.356 -106.784648)
		(end 181.56682 -106.573828)
		(width 0.127)
		(layer "In6.Cu")
		(net "H_CPU0_PROCHOT_LVC1_R_N")
	)
	(segment
		(start 210.481418 -117.335808)
		(end 210.024218 -116.878608)
		(width 0.127)
		(layer "In6.Cu")
		(net "H_CPU0_PROCHOT_LVC1_R_N")
	)
	(segment
		(start 181.356 -111.968788)
		(end 181.356 -106.784648)
		(width 0.127)
		(layer "In6.Cu")
		(net "H_CPU0_PROCHOT_LVC1_R_N")
	)
	(segment
		(start 248.376694 -118.01221)
		(end 244.07622 -118.01221)
		(width 0.127)
		(layer "In6.Cu")
		(net "H_CPU0_PROCHOT_LVC1_R_N")
	)
	(segment
		(start 255.45288 -126.710948)
		(end 255.32588 -126.583948)
		(width 0.127)
		(layer "In6.Cu")
		(net "H_CPU0_PROCHOT_LVC1_R_N")
	)
	(segment
		(start 244.07622 -118.01221)
		(end 240.035842 -113.971832)
		(width 0.127)
		(layer "In6.Cu")
		(net "H_CPU0_PROCHOT_LVC1_R_N")
	)
	(segment
		(start 199.4535 -113.65992)
		(end 198.82104 -113.02746)
		(width 0.127)
		(layer "In6.Cu")
		(net "H_CPU0_PROCHOT_LVC1_R_N")
	)
	(segment
		(start 349.712534 -228.99497)
		(end 349.712534 -228.459284)
		(width 0.12954)
		(layer "F.Cu")
		(net "H_CPU0_PROCHOT_LVC1_N")
	)
	(segment
		(start 349.712534 -228.459284)
		(end 349.71228 -228.45903)
		(width 0.12954)
		(layer "F.Cu")
		(net "H_CPU0_PROCHOT_LVC1_N")
	)
	(via
		(at 349.71228 -228.45903)
		(size 0.4572)
		(drill 0.2032)
		(layers "F.Cu" "B.Cu")
		(net "H_CPU0_PROCHOT_LVC1_N")
	)
	(via
		(at 322.811648 -222.852488)
		(size 0.6604)
		(drill 0.3302)
		(layers "F.Cu" "B.Cu")
		(net "H_CPU0_PROCHOT_LVC1_N")
	)
	(segment
		(start 320.50228 -190.541148)
		(end 319.297812 -189.33668)
		(width 0.12954)
		(layer "B.Cu")
		(net "H_CPU0_PROCHOT_LVC1_N")
	)
	(segment
		(start 335.413604 -228.1428)
		(end 335.08315 -228.335078)
		(width 0.0889)
		(layer "B.Cu")
		(net "H_CPU0_PROCHOT_LVC1_N")
	)
	(segment
		(start 343.886282 -228.134672)
		(end 343.87155 -228.143308)
		(width 0.0889)
		(layer "B.Cu")
		(net "H_CPU0_PROCHOT_LVC1_N")
	)
	(segment
		(start 345.766136 -228.134672)
		(end 345.755722 -228.140768)
		(width 0.0889)
		(layer "B.Cu")
		(net "H_CPU0_PROCHOT_LVC1_N")
	)
	(segment
		(start 327.25233 -227.29317)
		(end 322.811648 -222.852488)
		(width 0.12954)
		(layer "B.Cu")
		(net "H_CPU0_PROCHOT_LVC1_N")
	)
	(segment
		(start 342.946482 -228.134672)
		(end 342.93175 -228.143308)
		(width 0.0889)
		(layer "B.Cu")
		(net "H_CPU0_PROCHOT_LVC1_N")
	)
	(segment
		(start 336.367882 -228.134672)
		(end 336.357468 -228.140768)
		(width 0.0889)
		(layer "B.Cu")
		(net "H_CPU0_PROCHOT_LVC1_N")
	)
	(segment
		(start 349.71228 -228.45903)
		(end 349.21063 -228.209602)
		(width 0.0889)
		(layer "B.Cu")
		(net "H_CPU0_PROCHOT_LVC1_N")
	)
	(segment
		(start 331.268578 -228.335078)
		(end 330.22667 -227.29317)
		(width 0.12954)
		(layer "B.Cu")
		(net "H_CPU0_PROCHOT_LVC1_N")
	)
	(segment
		(start 334.032098 -228.335078)
		(end 331.268578 -228.335078)
		(width 0.12954)
		(layer "B.Cu")
		(net "H_CPU0_PROCHOT_LVC1_N")
	)
	(segment
		(start 337.307682 -228.134672)
		(end 337.29295 -228.143308)
		(width 0.0889)
		(layer "B.Cu")
		(net "H_CPU0_PROCHOT_LVC1_N")
	)
	(segment
		(start 342.006682 -228.134672)
		(end 341.99195 -228.143308)
		(width 0.0889)
		(layer "B.Cu")
		(net "H_CPU0_PROCHOT_LVC1_N")
	)
	(segment
		(start 335.428336 -228.134672)
		(end 335.41589 -228.14153)
		(width 0.0889)
		(layer "B.Cu")
		(net "H_CPU0_PROCHOT_LVC1_N")
	)
	(segment
		(start 318.223138 -188.30798)
		(end 318.223138 -189.33668)
		(width 0.12954)
		(layer "B.Cu")
		(net "H_CPU0_PROCHOT_LVC1_N")
	)
	(segment
		(start 344.826082 -228.134672)
		(end 344.81135 -228.143308)
		(width 0.0889)
		(layer "B.Cu")
		(net "H_CPU0_PROCHOT_LVC1_N")
	)
	(segment
		(start 335.08315 -228.335078)
		(end 334.032098 -228.335078)
		(width 0.0889)
		(layer "B.Cu")
		(net "H_CPU0_PROCHOT_LVC1_N")
	)
	(segment
		(start 322.811648 -222.852488)
		(end 318.850772 -218.891612)
		(width 0.12954)
		(layer "B.Cu")
		(net "H_CPU0_PROCHOT_LVC1_N")
	)
	(segment
		(start 335.41589 -228.14153)
		(end 335.413604 -228.1428)
		(width 0.0889)
		(layer "B.Cu")
		(net "H_CPU0_PROCHOT_LVC1_N")
	)
	(segment
		(start 319.297812 -189.33668)
		(end 318.223138 -189.33668)
		(width 0.12954)
		(layer "B.Cu")
		(net "H_CPU0_PROCHOT_LVC1_N")
	)
	(segment
		(start 318.850772 -218.891612)
		(end 318.850772 -196.31279)
		(width 0.12954)
		(layer "B.Cu")
		(net "H_CPU0_PROCHOT_LVC1_N")
	)
	(segment
		(start 339.187536 -228.134672)
		(end 339.177122 -228.140768)
		(width 0.0889)
		(layer "B.Cu")
		(net "H_CPU0_PROCHOT_LVC1_N")
	)
	(segment
		(start 348.585282 -228.134672)
		(end 348.57055 -228.143308)
		(width 0.0889)
		(layer "B.Cu")
		(net "H_CPU0_PROCHOT_LVC1_N")
	)
	(segment
		(start 346.705682 -228.134672)
		(end 346.695268 -228.140768)
		(width 0.0889)
		(layer "B.Cu")
		(net "H_CPU0_PROCHOT_LVC1_N")
	)
	(segment
		(start 318.850772 -196.31279)
		(end 320.50228 -194.661282)
		(width 0.12954)
		(layer "B.Cu")
		(net "H_CPU0_PROCHOT_LVC1_N")
	)
	(segment
		(start 330.22667 -227.29317)
		(end 327.25233 -227.29317)
		(width 0.12954)
		(layer "B.Cu")
		(net "H_CPU0_PROCHOT_LVC1_N")
	)
	(segment
		(start 341.066882 -228.134672)
		(end 341.05215 -228.143308)
		(width 0.0889)
		(layer "B.Cu")
		(net "H_CPU0_PROCHOT_LVC1_N")
	)
	(segment
		(start 320.50228 -194.661282)
		(end 320.50228 -190.541148)
		(width 0.12954)
		(layer "B.Cu")
		(net "H_CPU0_PROCHOT_LVC1_N")
	)
	(segment
		(start 339.572346 -228.140768)
		(end 339.561932 -228.134672)
		(width 0.0889)
		(layer "B.Cu")
		(net "H_CPU0_PROCHOT_LVC1_N")
	)
	(segment
		(start 338.247482 -228.134672)
		(end 338.23275 -228.143308)
		(width 0.0889)
		(layer "B.Cu")
		(net "H_CPU0_PROCHOT_LVC1_N")
	)
	(arc
		(start 345.755722 -228.140768)
		(mid 345.47729 -228.210582)
		(end 345.200478 -228.134672)
		(width 0.0889)
		(layer "B.Cu")
		(net "H_CPU0_PROCHOT_LVC1_N")
	)
	(arc
		(start 349.21063 -228.209602)
		(mid 349.080764 -228.186848)
		(end 348.959678 -228.134672)
		(width 0.0889)
		(layer "B.Cu")
		(net "H_CPU0_PROCHOT_LVC1_N")
	)
	(arc
		(start 342.93175 -228.143308)
		(mid 342.655309 -228.210474)
		(end 342.381078 -228.134672)
		(width 0.0889)
		(layer "B.Cu")
		(net "H_CPU0_PROCHOT_LVC1_N")
	)
	(arc
		(start 341.05215 -228.143308)
		(mid 340.775709 -228.210474)
		(end 340.501478 -228.134672)
		(width 0.0889)
		(layer "B.Cu")
		(net "H_CPU0_PROCHOT_LVC1_N")
	)
	(arc
		(start 335.802732 -228.134672)
		(mid 335.615534 -228.084529)
		(end 335.428336 -228.134672)
		(width 0.0889)
		(layer "B.Cu")
		(net "H_CPU0_PROCHOT_LVC1_N")
	)
	(arc
		(start 343.87155 -228.143308)
		(mid 343.595109 -228.210474)
		(end 343.320878 -228.134672)
		(width 0.0889)
		(layer "B.Cu")
		(net "H_CPU0_PROCHOT_LVC1_N")
	)
	(arc
		(start 346.140532 -228.134672)
		(mid 345.953334 -228.084529)
		(end 345.766136 -228.134672)
		(width 0.0889)
		(layer "B.Cu")
		(net "H_CPU0_PROCHOT_LVC1_N")
	)
	(arc
		(start 345.200478 -228.134672)
		(mid 345.01328 -228.084529)
		(end 344.826082 -228.134672)
		(width 0.0889)
		(layer "B.Cu")
		(net "H_CPU0_PROCHOT_LVC1_N")
	)
	(arc
		(start 347.080078 -228.134672)
		(mid 346.89288 -228.084529)
		(end 346.705682 -228.134672)
		(width 0.0889)
		(layer "B.Cu")
		(net "H_CPU0_PROCHOT_LVC1_N")
	)
	(arc
		(start 339.177122 -228.140768)
		(mid 338.89869 -228.210582)
		(end 338.621878 -228.134672)
		(width 0.0889)
		(layer "B.Cu")
		(net "H_CPU0_PROCHOT_LVC1_N")
	)
	(arc
		(start 348.959678 -228.134672)
		(mid 348.77248 -228.084529)
		(end 348.585282 -228.134672)
		(width 0.0889)
		(layer "B.Cu")
		(net "H_CPU0_PROCHOT_LVC1_N")
	)
	(arc
		(start 337.29295 -228.143308)
		(mid 337.016509 -228.210474)
		(end 336.742278 -228.134672)
		(width 0.0889)
		(layer "B.Cu")
		(net "H_CPU0_PROCHOT_LVC1_N")
	)
	(arc
		(start 347.645482 -228.134672)
		(mid 347.36278 -228.210414)
		(end 347.080078 -228.134672)
		(width 0.0889)
		(layer "B.Cu")
		(net "H_CPU0_PROCHOT_LVC1_N")
	)
	(arc
		(start 348.019878 -228.134672)
		(mid 347.83268 -228.084529)
		(end 347.645482 -228.134672)
		(width 0.0889)
		(layer "B.Cu")
		(net "H_CPU0_PROCHOT_LVC1_N")
	)
	(arc
		(start 336.742278 -228.134672)
		(mid 336.55508 -228.084529)
		(end 336.367882 -228.134672)
		(width 0.0889)
		(layer "B.Cu")
		(net "H_CPU0_PROCHOT_LVC1_N")
	)
	(arc
		(start 341.99195 -228.143308)
		(mid 341.715509 -228.210474)
		(end 341.441278 -228.134672)
		(width 0.0889)
		(layer "B.Cu")
		(net "H_CPU0_PROCHOT_LVC1_N")
	)
	(arc
		(start 340.127082 -228.134672)
		(mid 339.850523 -228.210381)
		(end 339.572346 -228.140768)
		(width 0.0889)
		(layer "B.Cu")
		(net "H_CPU0_PROCHOT_LVC1_N")
	)
	(arc
		(start 344.81135 -228.143308)
		(mid 344.534909 -228.210474)
		(end 344.260678 -228.134672)
		(width 0.0889)
		(layer "B.Cu")
		(net "H_CPU0_PROCHOT_LVC1_N")
	)
	(arc
		(start 337.682078 -228.134672)
		(mid 337.49488 -228.084529)
		(end 337.307682 -228.134672)
		(width 0.0889)
		(layer "B.Cu")
		(net "H_CPU0_PROCHOT_LVC1_N")
	)
	(arc
		(start 346.695268 -228.140768)
		(mid 346.41709 -228.21046)
		(end 346.140532 -228.134672)
		(width 0.0889)
		(layer "B.Cu")
		(net "H_CPU0_PROCHOT_LVC1_N")
	)
	(arc
		(start 338.621878 -228.134672)
		(mid 338.43468 -228.084529)
		(end 338.247482 -228.134672)
		(width 0.0889)
		(layer "B.Cu")
		(net "H_CPU0_PROCHOT_LVC1_N")
	)
	(arc
		(start 339.561932 -228.134672)
		(mid 339.374734 -228.084529)
		(end 339.187536 -228.134672)
		(width 0.0889)
		(layer "B.Cu")
		(net "H_CPU0_PROCHOT_LVC1_N")
	)
	(arc
		(start 341.441278 -228.134672)
		(mid 341.25408 -228.084529)
		(end 341.066882 -228.134672)
		(width 0.0889)
		(layer "B.Cu")
		(net "H_CPU0_PROCHOT_LVC1_N")
	)
	(arc
		(start 344.260678 -228.134672)
		(mid 344.07348 -228.084529)
		(end 343.886282 -228.134672)
		(width 0.0889)
		(layer "B.Cu")
		(net "H_CPU0_PROCHOT_LVC1_N")
	)
	(arc
		(start 336.357468 -228.140768)
		(mid 336.07929 -228.21046)
		(end 335.802732 -228.134672)
		(width 0.0889)
		(layer "B.Cu")
		(net "H_CPU0_PROCHOT_LVC1_N")
	)
	(arc
		(start 348.57055 -228.143308)
		(mid 348.294109 -228.210474)
		(end 348.019878 -228.134672)
		(width 0.0889)
		(layer "B.Cu")
		(net "H_CPU0_PROCHOT_LVC1_N")
	)
	(arc
		(start 340.501478 -228.134672)
		(mid 340.31428 -228.084529)
		(end 340.127082 -228.134672)
		(width 0.0889)
		(layer "B.Cu")
		(net "H_CPU0_PROCHOT_LVC1_N")
	)
	(arc
		(start 342.381078 -228.134672)
		(mid 342.19388 -228.084529)
		(end 342.006682 -228.134672)
		(width 0.0889)
		(layer "B.Cu")
		(net "H_CPU0_PROCHOT_LVC1_N")
	)
	(arc
		(start 343.320878 -228.134672)
		(mid 343.13368 -228.084529)
		(end 342.946482 -228.134672)
		(width 0.0889)
		(layer "B.Cu")
		(net "H_CPU0_PROCHOT_LVC1_N")
	)
	(arc
		(start 338.23275 -228.143308)
		(mid 337.956309 -228.210474)
		(end 337.682078 -228.134672)
		(width 0.0889)
		(layer "B.Cu")
		(net "H_CPU0_PROCHOT_LVC1_N")
	)
	(segment
		(start 350.18218 -230.900732)
		(end 350.182434 -230.900478)
		(width 0.12954)
		(layer "F.Cu")
		(net "H_CPU0_PREQ_QS_GTL_R_N")
	)
	(segment
		(start 350.18218 -231.436418)
		(end 350.18218 -230.900732)
		(width 0.12954)
		(layer "F.Cu")
		(net "H_CPU0_PREQ_QS_GTL_R_N")
	)
	(via
		(at 316.504066 -222.525082)
		(size 0.6604)
		(drill 0.3302)
		(layers "F.Cu" "B.Cu")
		(net "H_CPU0_PREQ_QS_GTL_R_N")
	)
	(via
		(at 350.182434 -230.900478)
		(size 0.4572)
		(drill 0.2032)
		(layers "F.Cu" "B.Cu")
		(net "H_CPU0_PREQ_QS_GTL_R_N")
	)
	(segment
		(start 340.986364 -230.584756)
		(end 340.971632 -230.57612)
		(width 0.0889)
		(layer "B.Cu")
		(net "H_CPU0_PREQ_QS_GTL_R_N")
	)
	(segment
		(start 314.778898 -199.627236)
		(end 314.579508 -199.427846)
		(width 0.12954)
		(layer "B.Cu")
		(net "H_CPU0_PREQ_QS_GTL_R_N")
	)
	(segment
		(start 348.504764 -230.584756)
		(end 348.490032 -230.57612)
		(width 0.0889)
		(layer "B.Cu")
		(net "H_CPU0_PREQ_QS_GTL_R_N")
	)
	(segment
		(start 346.625164 -230.584756)
		(end 346.610432 -230.57612)
		(width 0.0889)
		(layer "B.Cu")
		(net "H_CPU0_PREQ_QS_GTL_R_N")
	)
	(segment
		(start 329.513692 -230.87457)
		(end 324.853554 -230.87457)
		(width 0.12954)
		(layer "B.Cu")
		(net "H_CPU0_PREQ_QS_GTL_R_N")
	)
	(segment
		(start 345.295982 -230.57612)
		(end 345.285568 -230.582216)
		(width 0.0889)
		(layer "B.Cu")
		(net "H_CPU0_PREQ_QS_GTL_R_N")
	)
	(segment
		(start 350.02597 -230.62946)
		(end 349.936816 -230.605584)
		(width 0.0889)
		(layer "B.Cu")
		(net "H_CPU0_PREQ_QS_GTL_R_N")
	)
	(segment
		(start 341.926164 -230.584756)
		(end 341.911432 -230.57612)
		(width 0.0889)
		(layer "B.Cu")
		(net "H_CPU0_PREQ_QS_GTL_R_N")
	)
	(segment
		(start 313.425078 -195.23837)
		(end 313.425078 -194.295522)
		(width 0.12954)
		(layer "B.Cu")
		(net "H_CPU0_PREQ_QS_GTL_R_N")
	)
	(segment
		(start 313.719718 -195.53301)
		(end 313.425078 -195.23837)
		(width 0.12954)
		(layer "B.Cu")
		(net "H_CPU0_PREQ_QS_GTL_R_N")
	)
	(segment
		(start 349.444564 -230.584756)
		(end 349.429832 -230.57612)
		(width 0.0889)
		(layer "B.Cu")
		(net "H_CPU0_PREQ_QS_GTL_R_N")
	)
	(segment
		(start 336.085434 -230.525574)
		(end 335.666842 -230.525574)
		(width 0.0889)
		(layer "B.Cu")
		(net "H_CPU0_PREQ_QS_GTL_R_N")
	)
	(segment
		(start 339.102192 -230.582216)
		(end 339.091778 -230.57612)
		(width 0.0889)
		(layer "B.Cu")
		(net "H_CPU0_PREQ_QS_GTL_R_N")
	)
	(segment
		(start 338.717382 -230.57612)
		(end 338.706968 -230.582216)
		(width 0.0889)
		(layer "B.Cu")
		(net "H_CPU0_PREQ_QS_GTL_R_N")
	)
	(segment
		(start 316.504066 -222.525082)
		(end 314.778898 -220.799914)
		(width 0.12954)
		(layer "B.Cu")
		(net "H_CPU0_PREQ_QS_GTL_R_N")
	)
	(segment
		(start 329.515978 -230.876856)
		(end 329.513692 -230.87457)
		(width 0.12954)
		(layer "B.Cu")
		(net "H_CPU0_PREQ_QS_GTL_R_N")
	)
	(segment
		(start 340.046564 -230.584756)
		(end 340.031832 -230.57612)
		(width 0.0889)
		(layer "B.Cu")
		(net "H_CPU0_PREQ_QS_GTL_R_N")
	)
	(segment
		(start 343.805764 -230.584756)
		(end 343.791032 -230.57612)
		(width 0.0889)
		(layer "B.Cu")
		(net "H_CPU0_PREQ_QS_GTL_R_N")
	)
	(segment
		(start 336.287364 -230.584756)
		(end 336.272632 -230.57612)
		(width 0.0889)
		(layer "B.Cu")
		(net "H_CPU0_PREQ_QS_GTL_R_N")
	)
	(segment
		(start 333.722218 -230.876856)
		(end 329.515978 -230.876856)
		(width 0.12954)
		(layer "B.Cu")
		(net "H_CPU0_PREQ_QS_GTL_R_N")
	)
	(segment
		(start 350.182434 -230.900478)
		(end 350.02597 -230.62946)
		(width 0.0889)
		(layer "B.Cu")
		(net "H_CPU0_PREQ_QS_GTL_R_N")
	)
	(segment
		(start 313.425078 -194.295522)
		(end 313.78144 -193.93916)
		(width 0.12954)
		(layer "B.Cu")
		(net "H_CPU0_PREQ_QS_GTL_R_N")
	)
	(segment
		(start 335.31556 -230.876856)
		(end 333.722218 -230.876856)
		(width 0.0889)
		(layer "B.Cu")
		(net "H_CPU0_PREQ_QS_GTL_R_N")
	)
	(segment
		(start 314.357258 -195.53301)
		(end 313.719718 -195.53301)
		(width 0.12954)
		(layer "B.Cu")
		(net "H_CPU0_PREQ_QS_GTL_R_N")
	)
	(segment
		(start 314.778898 -220.799914)
		(end 314.778898 -199.627236)
		(width 0.12954)
		(layer "B.Cu")
		(net "H_CPU0_PREQ_QS_GTL_R_N")
	)
	(segment
		(start 335.666842 -230.525574)
		(end 335.31556 -230.876856)
		(width 0.0889)
		(layer "B.Cu")
		(net "H_CPU0_PREQ_QS_GTL_R_N")
	)
	(segment
		(start 324.853554 -230.87457)
		(end 316.504066 -222.525082)
		(width 0.12954)
		(layer "B.Cu")
		(net "H_CPU0_PREQ_QS_GTL_R_N")
	)
	(segment
		(start 337.227164 -230.584756)
		(end 337.212432 -230.57612)
		(width 0.0889)
		(layer "B.Cu")
		(net "H_CPU0_PREQ_QS_GTL_R_N")
	)
	(segment
		(start 314.579508 -195.75526)
		(end 314.357258 -195.53301)
		(width 0.12954)
		(layer "B.Cu")
		(net "H_CPU0_PREQ_QS_GTL_R_N")
	)
	(segment
		(start 345.680792 -230.582216)
		(end 345.670378 -230.57612)
		(width 0.0889)
		(layer "B.Cu")
		(net "H_CPU0_PREQ_QS_GTL_R_N")
	)
	(segment
		(start 342.865964 -230.584756)
		(end 342.851232 -230.57612)
		(width 0.0889)
		(layer "B.Cu")
		(net "H_CPU0_PREQ_QS_GTL_R_N")
	)
	(segment
		(start 314.579508 -199.427846)
		(end 314.579508 -195.75526)
		(width 0.12954)
		(layer "B.Cu")
		(net "H_CPU0_PREQ_QS_GTL_R_N")
	)
	(segment
		(start 347.564964 -230.584756)
		(end 347.550232 -230.57612)
		(width 0.0889)
		(layer "B.Cu")
		(net "H_CPU0_PREQ_QS_GTL_R_N")
	)
	(arc
		(start 349.055436 -230.57612)
		(mid 348.781237 -230.651955)
		(end 348.504764 -230.584756)
		(width 0.0889)
		(layer "B.Cu")
		(net "H_CPU0_PREQ_QS_GTL_R_N")
	)
	(arc
		(start 339.091778 -230.57612)
		(mid 338.90458 -230.525977)
		(end 338.717382 -230.57612)
		(width 0.0889)
		(layer "B.Cu")
		(net "H_CPU0_PREQ_QS_GTL_R_N")
	)
	(arc
		(start 340.597236 -230.57612)
		(mid 340.323037 -230.651955)
		(end 340.046564 -230.584756)
		(width 0.0889)
		(layer "B.Cu")
		(net "H_CPU0_PREQ_QS_GTL_R_N")
	)
	(arc
		(start 344.356436 -230.57612)
		(mid 344.082237 -230.651955)
		(end 343.805764 -230.584756)
		(width 0.0889)
		(layer "B.Cu")
		(net "H_CPU0_PREQ_QS_GTL_R_N")
	)
	(arc
		(start 337.212432 -230.57612)
		(mid 337.025234 -230.525977)
		(end 336.838036 -230.57612)
		(width 0.0889)
		(layer "B.Cu")
		(net "H_CPU0_PREQ_QS_GTL_R_N")
	)
	(arc
		(start 345.285568 -230.582216)
		(mid 345.00739 -230.651939)
		(end 344.730832 -230.57612)
		(width 0.0889)
		(layer "B.Cu")
		(net "H_CPU0_PREQ_QS_GTL_R_N")
	)
	(arc
		(start 347.550232 -230.57612)
		(mid 347.363034 -230.525977)
		(end 347.175836 -230.57612)
		(width 0.0889)
		(layer "B.Cu")
		(net "H_CPU0_PREQ_QS_GTL_R_N")
	)
	(arc
		(start 348.490032 -230.57612)
		(mid 348.302834 -230.525977)
		(end 348.115636 -230.57612)
		(width 0.0889)
		(layer "B.Cu")
		(net "H_CPU0_PREQ_QS_GTL_R_N")
	)
	(arc
		(start 336.272632 -230.57612)
		(mid 336.18236 -230.538521)
		(end 336.085434 -230.525574)
		(width 0.0889)
		(layer "B.Cu")
		(net "H_CPU0_PREQ_QS_GTL_R_N")
	)
	(arc
		(start 338.706968 -230.582216)
		(mid 338.42879 -230.651939)
		(end 338.152232 -230.57612)
		(width 0.0889)
		(layer "B.Cu")
		(net "H_CPU0_PREQ_QS_GTL_R_N")
	)
	(arc
		(start 347.175836 -230.57612)
		(mid 346.901637 -230.651955)
		(end 346.625164 -230.584756)
		(width 0.0889)
		(layer "B.Cu")
		(net "H_CPU0_PREQ_QS_GTL_R_N")
	)
	(arc
		(start 342.851232 -230.57612)
		(mid 342.664034 -230.525977)
		(end 342.476836 -230.57612)
		(width 0.0889)
		(layer "B.Cu")
		(net "H_CPU0_PREQ_QS_GTL_R_N")
	)
	(arc
		(start 349.429832 -230.57612)
		(mid 349.242634 -230.525977)
		(end 349.055436 -230.57612)
		(width 0.0889)
		(layer "B.Cu")
		(net "H_CPU0_PREQ_QS_GTL_R_N")
	)
	(arc
		(start 344.730832 -230.57612)
		(mid 344.543634 -230.525977)
		(end 344.356436 -230.57612)
		(width 0.0889)
		(layer "B.Cu")
		(net "H_CPU0_PREQ_QS_GTL_R_N")
	)
	(arc
		(start 346.610432 -230.57612)
		(mid 346.423234 -230.525977)
		(end 346.236036 -230.57612)
		(width 0.0889)
		(layer "B.Cu")
		(net "H_CPU0_PREQ_QS_GTL_R_N")
	)
	(arc
		(start 348.115636 -230.57612)
		(mid 347.841437 -230.651955)
		(end 347.564964 -230.584756)
		(width 0.0889)
		(layer "B.Cu")
		(net "H_CPU0_PREQ_QS_GTL_R_N")
	)
	(arc
		(start 340.971632 -230.57612)
		(mid 340.784434 -230.525977)
		(end 340.597236 -230.57612)
		(width 0.0889)
		(layer "B.Cu")
		(net "H_CPU0_PREQ_QS_GTL_R_N")
	)
	(arc
		(start 343.416636 -230.57612)
		(mid 343.142437 -230.651955)
		(end 342.865964 -230.584756)
		(width 0.0889)
		(layer "B.Cu")
		(net "H_CPU0_PREQ_QS_GTL_R_N")
	)
	(arc
		(start 336.838036 -230.57612)
		(mid 336.563837 -230.651955)
		(end 336.287364 -230.584756)
		(width 0.0889)
		(layer "B.Cu")
		(net "H_CPU0_PREQ_QS_GTL_R_N")
	)
	(arc
		(start 341.537036 -230.57612)
		(mid 341.262837 -230.651955)
		(end 340.986364 -230.584756)
		(width 0.0889)
		(layer "B.Cu")
		(net "H_CPU0_PREQ_QS_GTL_R_N")
	)
	(arc
		(start 343.791032 -230.57612)
		(mid 343.603834 -230.525977)
		(end 343.416636 -230.57612)
		(width 0.0889)
		(layer "B.Cu")
		(net "H_CPU0_PREQ_QS_GTL_R_N")
	)
	(arc
		(start 337.777836 -230.57612)
		(mid 337.503637 -230.651955)
		(end 337.227164 -230.584756)
		(width 0.0889)
		(layer "B.Cu")
		(net "H_CPU0_PREQ_QS_GTL_R_N")
	)
	(arc
		(start 340.031832 -230.57612)
		(mid 339.844634 -230.525977)
		(end 339.657436 -230.57612)
		(width 0.0889)
		(layer "B.Cu")
		(net "H_CPU0_PREQ_QS_GTL_R_N")
	)
	(arc
		(start 341.911432 -230.57612)
		(mid 341.724234 -230.525977)
		(end 341.537036 -230.57612)
		(width 0.0889)
		(layer "B.Cu")
		(net "H_CPU0_PREQ_QS_GTL_R_N")
	)
	(arc
		(start 345.670378 -230.57612)
		(mid 345.48318 -230.525977)
		(end 345.295982 -230.57612)
		(width 0.0889)
		(layer "B.Cu")
		(net "H_CPU0_PREQ_QS_GTL_R_N")
	)
	(arc
		(start 349.936816 -230.605584)
		(mid 349.688311 -230.651571)
		(end 349.444564 -230.584756)
		(width 0.0889)
		(layer "B.Cu")
		(net "H_CPU0_PREQ_QS_GTL_R_N")
	)
	(arc
		(start 346.236036 -230.57612)
		(mid 345.959223 -230.65199)
		(end 345.680792 -230.582216)
		(width 0.0889)
		(layer "B.Cu")
		(net "H_CPU0_PREQ_QS_GTL_R_N")
	)
	(arc
		(start 342.476836 -230.57612)
		(mid 342.202637 -230.651955)
		(end 341.926164 -230.584756)
		(width 0.0889)
		(layer "B.Cu")
		(net "H_CPU0_PREQ_QS_GTL_R_N")
	)
	(arc
		(start 338.152232 -230.57612)
		(mid 337.965034 -230.525977)
		(end 337.777836 -230.57612)
		(width 0.0889)
		(layer "B.Cu")
		(net "H_CPU0_PREQ_QS_GTL_R_N")
	)
	(arc
		(start 339.657436 -230.57612)
		(mid 339.380623 -230.65199)
		(end 339.102192 -230.582216)
		(width 0.0889)
		(layer "B.Cu")
		(net "H_CPU0_PREQ_QS_GTL_R_N")
	)
	(segment
		(start 357.70058 -234.69219)
		(end 357.70058 -234.156504)
		(width 0.12954)
		(layer "F.Cu")
		(net "H_CPU0_PRDY_QS_GTL_R_N")
	)
	(segment
		(start 357.70058 -234.156504)
		(end 357.700834 -234.15625)
		(width 0.12954)
		(layer "F.Cu")
		(net "H_CPU0_PRDY_QS_GTL_R_N")
	)
	(via
		(at 357.700834 -234.15625)
		(size 0.4572)
		(drill 0.2032)
		(layers "F.Cu" "B.Cu")
		(net "H_CPU0_PRDY_QS_GTL_R_N")
	)
	(via
		(at 324.622922 -219.009468)
		(size 0.6604)
		(drill 0.3302)
		(layers "F.Cu" "B.Cu")
		(net "H_CPU0_PRDY_QS_GTL_R_N")
	)
	(segment
		(start 351.787968 -228.139752)
		(end 351.779078 -228.134672)
		(width 0.0889)
		(layer "B.Cu")
		(net "H_CPU0_PRDY_QS_GTL_R_N")
	)
	(segment
		(start 332.998064 -224.887536)
		(end 332.983332 -224.8789)
		(width 0.0889)
		(layer "B.Cu")
		(net "H_CPU0_PRDY_QS_GTL_R_N")
	)
	(segment
		(start 350.848168 -226.511866)
		(end 350.839278 -226.506786)
		(width 0.0889)
		(layer "B.Cu")
		(net "H_CPU0_PRDY_QS_GTL_R_N")
	)
	(segment
		(start 349.444564 -225.701606)
		(end 349.429832 -225.69297)
		(width 0.0889)
		(layer "B.Cu")
		(net "H_CPU0_PRDY_QS_GTL_R_N")
	)
	(segment
		(start 324.622922 -219.009468)
		(end 323.869812 -218.256358)
		(width 0.12954)
		(layer "B.Cu")
		(net "H_CPU0_PRDY_QS_GTL_R_N")
	)
	(segment
		(start 352.436684 -229.28834)
		(end 352.436684 -229.272846)
		(width 0.0889)
		(layer "B.Cu")
		(net "H_CPU0_PRDY_QS_GTL_R_N")
	)
	(segment
		(start 345.685364 -225.701606)
		(end 345.670632 -225.69297)
		(width 0.0889)
		(layer "B.Cu")
		(net "H_CPU0_PRDY_QS_GTL_R_N")
	)
	(segment
		(start 323.869812 -191.756284)
		(end 323.646292 -191.532764)
		(width 0.12954)
		(layer "B.Cu")
		(net "H_CPU0_PRDY_QS_GTL_R_N")
	)
	(segment
		(start 335.990184 -225.2218)
		(end 335.990184 -225.203258)
		(width 0.0889)
		(layer "B.Cu")
		(net "H_CPU0_PRDY_QS_GTL_R_N")
	)
	(segment
		(start 356.486968 -233.022902)
		(end 356.478078 -233.017822)
		(width 0.0889)
		(layer "B.Cu")
		(net "H_CPU0_PRDY_QS_GTL_R_N")
	)
	(segment
		(start 339.102192 -225.699066)
		(end 339.091778 -225.69297)
		(width 0.0889)
		(layer "B.Cu")
		(net "H_CPU0_PRDY_QS_GTL_R_N")
	)
	(segment
		(start 341.926164 -225.701606)
		(end 341.911432 -225.69297)
		(width 0.0889)
		(layer "B.Cu")
		(net "H_CPU0_PRDY_QS_GTL_R_N")
	)
	(segment
		(start 331.564742 -224.493074)
		(end 330.106528 -224.493074)
		(width 0.12954)
		(layer "B.Cu")
		(net "H_CPU0_PRDY_QS_GTL_R_N")
	)
	(segment
		(start 356.195884 -232.543858)
		(end 356.195884 -232.528364)
		(width 0.0889)
		(layer "B.Cu")
		(net "H_CPU0_PRDY_QS_GTL_R_N")
	)
	(segment
		(start 330.106528 -224.493074)
		(end 324.622922 -219.009468)
		(width 0.12954)
		(layer "B.Cu")
		(net "H_CPU0_PRDY_QS_GTL_R_N")
	)
	(segment
		(start 356.017322 -232.209086)
		(end 356.002336 -232.20045)
		(width 0.0889)
		(layer "B.Cu")
		(net "H_CPU0_PRDY_QS_GTL_R_N")
	)
	(segment
		(start 356.66553 -233.356404)
		(end 356.66553 -233.34218)
		(width 0.0889)
		(layer "B.Cu")
		(net "H_CPU0_PRDY_QS_GTL_R_N")
	)
	(segment
		(start 354.137722 -230.5812)
		(end 354.11664 -230.569008)
		(width 0.0889)
		(layer "B.Cu")
		(net "H_CPU0_PRDY_QS_GTL_R_N")
	)
	(segment
		(start 354.979986 -231.967786)
		(end 354.874576 -231.862376)
		(width 0.0889)
		(layer "B.Cu")
		(net "H_CPU0_PRDY_QS_GTL_R_N")
	)
	(segment
		(start 355.68001 -232.113328)
		(end 355.331268 -232.113328)
		(width 0.0889)
		(layer "B.Cu")
		(net "H_CPU0_PRDY_QS_GTL_R_N")
	)
	(segment
		(start 346.625164 -225.701606)
		(end 346.610432 -225.69297)
		(width 0.0889)
		(layer "B.Cu")
		(net "H_CPU0_PRDY_QS_GTL_R_N")
	)
	(segment
		(start 353.284282 -229.762304)
		(end 353.26955 -229.77094)
		(width 0.0889)
		(layer "B.Cu")
		(net "H_CPU0_PRDY_QS_GTL_R_N")
	)
	(segment
		(start 344.745564 -225.701606)
		(end 344.730832 -225.69297)
		(width 0.0889)
		(layer "B.Cu")
		(net "H_CPU0_PRDY_QS_GTL_R_N")
	)
	(segment
		(start 343.805764 -225.701606)
		(end 343.791032 -225.69297)
		(width 0.0889)
		(layer "B.Cu")
		(net "H_CPU0_PRDY_QS_GTL_R_N")
	)
	(segment
		(start 340.986364 -225.701606)
		(end 340.971632 -225.69297)
		(width 0.0889)
		(layer "B.Cu")
		(net "H_CPU0_PRDY_QS_GTL_R_N")
	)
	(segment
		(start 331.900022 -224.828354)
		(end 331.564742 -224.493074)
		(width 0.12954)
		(layer "B.Cu")
		(net "H_CPU0_PRDY_QS_GTL_R_N")
	)
	(segment
		(start 323.646292 -191.532764)
		(end 323.646292 -190.669164)
		(width 0.12954)
		(layer "B.Cu")
		(net "H_CPU0_PRDY_QS_GTL_R_N")
	)
	(segment
		(start 347.564964 -225.701606)
		(end 347.550232 -225.69297)
		(width 0.0889)
		(layer "B.Cu")
		(net "H_CPU0_PRDY_QS_GTL_R_N")
	)
	(segment
		(start 348.504764 -225.701606)
		(end 348.490032 -225.69297)
		(width 0.0889)
		(layer "B.Cu")
		(net "H_CPU0_PRDY_QS_GTL_R_N")
	)
	(segment
		(start 351.496884 -227.667058)
		(end 351.496884 -227.64496)
		(width 0.0889)
		(layer "B.Cu")
		(net "H_CPU0_PRDY_QS_GTL_R_N")
	)
	(segment
		(start 335.811622 -224.88398)
		(end 335.802732 -224.8789)
		(width 0.0889)
		(layer "B.Cu")
		(net "H_CPU0_PRDY_QS_GTL_R_N")
	)
	(segment
		(start 332.337918 -224.828354)
		(end 331.900022 -224.828354)
		(width 0.12954)
		(layer "B.Cu")
		(net "H_CPU0_PRDY_QS_GTL_R_N")
	)
	(segment
		(start 342.865964 -225.701606)
		(end 342.851232 -225.69297)
		(width 0.0889)
		(layer "B.Cu")
		(net "H_CPU0_PRDY_QS_GTL_R_N")
	)
	(segment
		(start 332.796134 -224.828354)
		(end 332.337918 -224.828354)
		(width 0.0889)
		(layer "B.Cu")
		(net "H_CPU0_PRDY_QS_GTL_R_N")
	)
	(segment
		(start 338.162646 -225.699066)
		(end 338.152232 -225.69297)
		(width 0.0889)
		(layer "B.Cu")
		(net "H_CPU0_PRDY_QS_GTL_R_N")
	)
	(segment
		(start 357.329486 -234.055412)
		(end 356.948232 -233.831892)
		(width 0.0889)
		(layer "B.Cu")
		(net "H_CPU0_PRDY_QS_GTL_R_N")
	)
	(segment
		(start 323.869812 -218.256358)
		(end 323.869812 -191.756284)
		(width 0.12954)
		(layer "B.Cu")
		(net "H_CPU0_PRDY_QS_GTL_R_N")
	)
	(segment
		(start 350.557084 -226.032822)
		(end 350.557084 -226.017328)
		(width 0.0889)
		(layer "B.Cu")
		(net "H_CPU0_PRDY_QS_GTL_R_N")
	)
	(segment
		(start 337.227164 -225.701606)
		(end 337.212432 -225.69297)
		(width 0.0889)
		(layer "B.Cu")
		(net "H_CPU0_PRDY_QS_GTL_R_N")
	)
	(segment
		(start 340.046564 -225.701606)
		(end 340.031832 -225.69297)
		(width 0.0889)
		(layer "B.Cu")
		(net "H_CPU0_PRDY_QS_GTL_R_N")
	)
	(segment
		(start 351.318322 -227.325682)
		(end 351.29724 -227.31349)
		(width 0.0889)
		(layer "B.Cu")
		(net "H_CPU0_PRDY_QS_GTL_R_N")
	)
	(segment
		(start 352.258122 -228.953568)
		(end 352.243136 -228.944932)
		(width 0.0889)
		(layer "B.Cu")
		(net "H_CPU0_PRDY_QS_GTL_R_N")
	)
	(arc
		(start 349.429832 -225.69297)
		(mid 349.242634 -225.642827)
		(end 349.055436 -225.69297)
		(width 0.0889)
		(layer "B.Cu")
		(net "H_CPU0_PRDY_QS_GTL_R_N")
	)
	(arc
		(start 353.26955 -229.77094)
		(mid 352.718357 -229.762142)
		(end 352.436684 -229.28834)
		(width 0.0889)
		(layer "B.Cu")
		(net "H_CPU0_PRDY_QS_GTL_R_N")
	)
	(arc
		(start 353.84613 -230.086662)
		(mid 353.658831 -229.762221)
		(end 353.284282 -229.762304)
		(width 0.0889)
		(layer "B.Cu")
		(net "H_CPU0_PRDY_QS_GTL_R_N")
	)
	(arc
		(start 354.316284 -230.900478)
		(mid 354.268605 -230.717578)
		(end 354.137722 -230.5812)
		(width 0.0889)
		(layer "B.Cu")
		(net "H_CPU0_PRDY_QS_GTL_R_N")
	)
	(arc
		(start 352.436684 -229.272846)
		(mid 352.389005 -229.089946)
		(end 352.258122 -228.953568)
		(width 0.0889)
		(layer "B.Cu")
		(net "H_CPU0_PRDY_QS_GTL_R_N")
	)
	(arc
		(start 342.851232 -225.69297)
		(mid 342.664034 -225.642827)
		(end 342.476836 -225.69297)
		(width 0.0889)
		(layer "B.Cu")
		(net "H_CPU0_PRDY_QS_GTL_R_N")
	)
	(arc
		(start 347.175836 -225.69297)
		(mid 346.901607 -225.768895)
		(end 346.625164 -225.701606)
		(width 0.0889)
		(layer "B.Cu")
		(net "H_CPU0_PRDY_QS_GTL_R_N")
	)
	(arc
		(start 351.29724 -227.31349)
		(mid 351.099012 -227.107642)
		(end 351.02673 -226.831144)
		(width 0.0889)
		(layer "B.Cu")
		(net "H_CPU0_PRDY_QS_GTL_R_N")
	)
	(arc
		(start 356.002336 -232.20045)
		(mid 355.846961 -232.135468)
		(end 355.68001 -232.113328)
		(width 0.0889)
		(layer "B.Cu")
		(net "H_CPU0_PRDY_QS_GTL_R_N")
	)
	(arc
		(start 339.657436 -225.69297)
		(mid 339.380623 -225.768806)
		(end 339.102192 -225.699066)
		(width 0.0889)
		(layer "B.Cu")
		(net "H_CPU0_PRDY_QS_GTL_R_N")
	)
	(arc
		(start 343.416636 -225.69297)
		(mid 343.142407 -225.768895)
		(end 342.865964 -225.701606)
		(width 0.0889)
		(layer "B.Cu")
		(net "H_CPU0_PRDY_QS_GTL_R_N")
	)
	(arc
		(start 354.874576 -231.862376)
		(mid 354.820458 -231.781383)
		(end 354.801424 -231.685846)
		(width 0.0889)
		(layer "B.Cu")
		(net "H_CPU0_PRDY_QS_GTL_R_N")
	)
	(arc
		(start 346.236036 -225.69297)
		(mid 345.961807 -225.768895)
		(end 345.685364 -225.701606)
		(width 0.0889)
		(layer "B.Cu")
		(net "H_CPU0_PRDY_QS_GTL_R_N")
	)
	(arc
		(start 356.66553 -233.34218)
		(mid 356.617851 -233.15928)
		(end 356.486968 -233.022902)
		(width 0.0889)
		(layer "B.Cu")
		(net "H_CPU0_PRDY_QS_GTL_R_N")
	)
	(arc
		(start 355.331268 -232.113328)
		(mid 355.141142 -232.07551)
		(end 354.979986 -231.967786)
		(width 0.0889)
		(layer "B.Cu")
		(net "H_CPU0_PRDY_QS_GTL_R_N")
	)
	(arc
		(start 356.478078 -233.017822)
		(mid 356.275255 -232.817591)
		(end 356.195884 -232.543858)
		(width 0.0889)
		(layer "B.Cu")
		(net "H_CPU0_PRDY_QS_GTL_R_N")
	)
	(arc
		(start 338.152232 -225.69297)
		(mid 337.965034 -225.642827)
		(end 337.777836 -225.69297)
		(width 0.0889)
		(layer "B.Cu")
		(net "H_CPU0_PRDY_QS_GTL_R_N")
	)
	(arc
		(start 341.911432 -225.69297)
		(mid 341.724234 -225.642827)
		(end 341.537036 -225.69297)
		(width 0.0889)
		(layer "B.Cu")
		(net "H_CPU0_PRDY_QS_GTL_R_N")
	)
	(arc
		(start 335.428336 -224.8789)
		(mid 335.145634 -224.954676)
		(end 334.862932 -224.8789)
		(width 0.0889)
		(layer "B.Cu")
		(net "H_CPU0_PRDY_QS_GTL_R_N")
	)
	(arc
		(start 343.791032 -225.69297)
		(mid 343.603834 -225.642827)
		(end 343.416636 -225.69297)
		(width 0.0889)
		(layer "B.Cu")
		(net "H_CPU0_PRDY_QS_GTL_R_N")
	)
	(arc
		(start 349.995236 -225.69297)
		(mid 349.721007 -225.768895)
		(end 349.444564 -225.701606)
		(width 0.0889)
		(layer "B.Cu")
		(net "H_CPU0_PRDY_QS_GTL_R_N")
	)
	(arc
		(start 342.476836 -225.69297)
		(mid 342.202607 -225.768895)
		(end 341.926164 -225.701606)
		(width 0.0889)
		(layer "B.Cu")
		(net "H_CPU0_PRDY_QS_GTL_R_N")
	)
	(arc
		(start 348.490032 -225.69297)
		(mid 348.302834 -225.642827)
		(end 348.115636 -225.69297)
		(width 0.0889)
		(layer "B.Cu")
		(net "H_CPU0_PRDY_QS_GTL_R_N")
	)
	(arc
		(start 345.296236 -225.69297)
		(mid 345.022007 -225.768895)
		(end 344.745564 -225.701606)
		(width 0.0889)
		(layer "B.Cu")
		(net "H_CPU0_PRDY_QS_GTL_R_N")
	)
	(arc
		(start 344.730832 -225.69297)
		(mid 344.543634 -225.642827)
		(end 344.356436 -225.69297)
		(width 0.0889)
		(layer "B.Cu")
		(net "H_CPU0_PRDY_QS_GTL_R_N")
	)
	(arc
		(start 335.990184 -225.203258)
		(mid 335.942505 -225.020358)
		(end 335.811622 -224.88398)
		(width 0.0889)
		(layer "B.Cu")
		(net "H_CPU0_PRDY_QS_GTL_R_N")
	)
	(arc
		(start 337.212432 -225.69297)
		(mid 337.025234 -225.642827)
		(end 336.838036 -225.69297)
		(width 0.0889)
		(layer "B.Cu")
		(net "H_CPU0_PRDY_QS_GTL_R_N")
	)
	(arc
		(start 356.948232 -233.831892)
		(mid 356.744751 -233.631088)
		(end 356.66553 -233.356404)
		(width 0.0889)
		(layer "B.Cu")
		(net "H_CPU0_PRDY_QS_GTL_R_N")
	)
	(arc
		(start 351.496884 -227.64496)
		(mid 351.449205 -227.46206)
		(end 351.318322 -227.325682)
		(width 0.0889)
		(layer "B.Cu")
		(net "H_CPU0_PRDY_QS_GTL_R_N")
	)
	(arc
		(start 339.091778 -225.69297)
		(mid 338.90458 -225.642827)
		(end 338.717382 -225.69297)
		(width 0.0889)
		(layer "B.Cu")
		(net "H_CPU0_PRDY_QS_GTL_R_N")
	)
	(arc
		(start 356.195884 -232.528364)
		(mid 356.148205 -232.345464)
		(end 356.017322 -232.209086)
		(width 0.0889)
		(layer "B.Cu")
		(net "H_CPU0_PRDY_QS_GTL_R_N")
	)
	(arc
		(start 350.839278 -226.506786)
		(mid 350.636455 -226.306555)
		(end 350.557084 -226.032822)
		(width 0.0889)
		(layer "B.Cu")
		(net "H_CPU0_PRDY_QS_GTL_R_N")
	)
	(arc
		(start 344.356436 -225.69297)
		(mid 344.082207 -225.768895)
		(end 343.805764 -225.701606)
		(width 0.0889)
		(layer "B.Cu")
		(net "H_CPU0_PRDY_QS_GTL_R_N")
	)
	(arc
		(start 338.717382 -225.69297)
		(mid 338.440823 -225.768679)
		(end 338.162646 -225.699066)
		(width 0.0889)
		(layer "B.Cu")
		(net "H_CPU0_PRDY_QS_GTL_R_N")
	)
	(arc
		(start 336.838036 -225.69297)
		(mid 336.555334 -225.768712)
		(end 336.272632 -225.69297)
		(width 0.0889)
		(layer "B.Cu")
		(net "H_CPU0_PRDY_QS_GTL_R_N")
	)
	(arc
		(start 335.802732 -224.8789)
		(mid 335.615534 -224.828757)
		(end 335.428336 -224.8789)
		(width 0.0889)
		(layer "B.Cu")
		(net "H_CPU0_PRDY_QS_GTL_R_N")
	)
	(arc
		(start 340.971632 -225.69297)
		(mid 340.784434 -225.642827)
		(end 340.597236 -225.69297)
		(width 0.0889)
		(layer "B.Cu")
		(net "H_CPU0_PRDY_QS_GTL_R_N")
	)
	(arc
		(start 346.610432 -225.69297)
		(mid 346.423234 -225.642827)
		(end 346.236036 -225.69297)
		(width 0.0889)
		(layer "B.Cu")
		(net "H_CPU0_PRDY_QS_GTL_R_N")
	)
	(arc
		(start 333.548736 -224.8789)
		(mid 333.274537 -224.954735)
		(end 332.998064 -224.887536)
		(width 0.0889)
		(layer "B.Cu")
		(net "H_CPU0_PRDY_QS_GTL_R_N")
	)
	(arc
		(start 354.11664 -230.569008)
		(mid 353.918412 -230.36316)
		(end 353.84613 -230.086662)
		(width 0.0889)
		(layer "B.Cu")
		(net "H_CPU0_PRDY_QS_GTL_R_N")
	)
	(arc
		(start 351.96653 -228.45903)
		(mid 351.918851 -228.27613)
		(end 351.787968 -228.139752)
		(width 0.0889)
		(layer "B.Cu")
		(net "H_CPU0_PRDY_QS_GTL_R_N")
	)
	(arc
		(start 347.550232 -225.69297)
		(mid 347.363034 -225.642827)
		(end 347.175836 -225.69297)
		(width 0.0889)
		(layer "B.Cu")
		(net "H_CPU0_PRDY_QS_GTL_R_N")
	)
	(arc
		(start 345.670632 -225.69297)
		(mid 345.483434 -225.642827)
		(end 345.296236 -225.69297)
		(width 0.0889)
		(layer "B.Cu")
		(net "H_CPU0_PRDY_QS_GTL_R_N")
	)
	(arc
		(start 340.031832 -225.69297)
		(mid 339.844634 -225.642827)
		(end 339.657436 -225.69297)
		(width 0.0889)
		(layer "B.Cu")
		(net "H_CPU0_PRDY_QS_GTL_R_N")
	)
	(arc
		(start 354.551234 -231.273096)
		(mid 354.379946 -231.120723)
		(end 354.316284 -230.900478)
		(width 0.0889)
		(layer "B.Cu")
		(net "H_CPU0_PRDY_QS_GTL_R_N")
	)
	(arc
		(start 351.02673 -226.831144)
		(mid 350.979051 -226.648244)
		(end 350.848168 -226.511866)
		(width 0.0889)
		(layer "B.Cu")
		(net "H_CPU0_PRDY_QS_GTL_R_N")
	)
	(arc
		(start 357.700834 -234.15625)
		(mid 357.508438 -234.130588)
		(end 357.329486 -234.055412)
		(width 0.0889)
		(layer "B.Cu")
		(net "H_CPU0_PRDY_QS_GTL_R_N")
	)
	(arc
		(start 354.801424 -231.685846)
		(mid 354.733995 -231.444515)
		(end 354.551234 -231.273096)
		(width 0.0889)
		(layer "B.Cu")
		(net "H_CPU0_PRDY_QS_GTL_R_N")
	)
	(arc
		(start 334.488536 -224.8789)
		(mid 334.205834 -224.954676)
		(end 333.923132 -224.8789)
		(width 0.0889)
		(layer "B.Cu")
		(net "H_CPU0_PRDY_QS_GTL_R_N")
	)
	(arc
		(start 337.777836 -225.69297)
		(mid 337.503607 -225.768895)
		(end 337.227164 -225.701606)
		(width 0.0889)
		(layer "B.Cu")
		(net "H_CPU0_PRDY_QS_GTL_R_N")
	)
	(arc
		(start 340.597236 -225.69297)
		(mid 340.323007 -225.768895)
		(end 340.046564 -225.701606)
		(width 0.0889)
		(layer "B.Cu")
		(net "H_CPU0_PRDY_QS_GTL_R_N")
	)
	(arc
		(start 352.243136 -228.944932)
		(mid 352.040549 -228.738581)
		(end 351.96653 -228.45903)
		(width 0.0889)
		(layer "B.Cu")
		(net "H_CPU0_PRDY_QS_GTL_R_N")
	)
	(arc
		(start 334.862932 -224.8789)
		(mid 334.675734 -224.828757)
		(end 334.488536 -224.8789)
		(width 0.0889)
		(layer "B.Cu")
		(net "H_CPU0_PRDY_QS_GTL_R_N")
	)
	(arc
		(start 333.923132 -224.8789)
		(mid 333.735934 -224.828757)
		(end 333.548736 -224.8789)
		(width 0.0889)
		(layer "B.Cu")
		(net "H_CPU0_PRDY_QS_GTL_R_N")
	)
	(arc
		(start 350.557084 -226.017328)
		(mid 350.369785 -225.692887)
		(end 349.995236 -225.69297)
		(width 0.0889)
		(layer "B.Cu")
		(net "H_CPU0_PRDY_QS_GTL_R_N")
	)
	(arc
		(start 336.272632 -225.69297)
		(mid 336.070346 -225.493989)
		(end 335.990184 -225.2218)
		(width 0.0889)
		(layer "B.Cu")
		(net "H_CPU0_PRDY_QS_GTL_R_N")
	)
	(arc
		(start 349.055436 -225.69297)
		(mid 348.781207 -225.768895)
		(end 348.504764 -225.701606)
		(width 0.0889)
		(layer "B.Cu")
		(net "H_CPU0_PRDY_QS_GTL_R_N")
	)
	(arc
		(start 348.115636 -225.69297)
		(mid 347.841407 -225.768895)
		(end 347.564964 -225.701606)
		(width 0.0889)
		(layer "B.Cu")
		(net "H_CPU0_PRDY_QS_GTL_R_N")
	)
	(arc
		(start 332.983332 -224.8789)
		(mid 332.89306 -224.841301)
		(end 332.796134 -224.828354)
		(width 0.0889)
		(layer "B.Cu")
		(net "H_CPU0_PRDY_QS_GTL_R_N")
	)
	(arc
		(start 351.779078 -228.134672)
		(mid 351.577796 -227.937185)
		(end 351.496884 -227.667058)
		(width 0.0889)
		(layer "B.Cu")
		(net "H_CPU0_PRDY_QS_GTL_R_N")
	)
	(arc
		(start 341.537036 -225.69297)
		(mid 341.262807 -225.768895)
		(end 340.986364 -225.701606)
		(width 0.0889)
		(layer "B.Cu")
		(net "H_CPU0_PRDY_QS_GTL_R_N")
	)
	(segment
		(start 367.098834 -229.808532)
		(end 367.098834 -229.272846)
		(width 0.12954)
		(layer "F.Cu")
		(net "H_CPU0_PM_FAST_WAKE_N")
	)
	(segment
		(start 367.09858 -229.808786)
		(end 367.098834 -229.808532)
		(width 0.12954)
		(layer "F.Cu")
		(net "H_CPU0_PM_FAST_WAKE_N")
	)
	(via
		(at 381.69723 -193.01841)
		(size 0.6604)
		(drill 0.3302)
		(layers "F.Cu" "B.Cu")
		(net "H_CPU0_PM_FAST_WAKE_N")
	)
	(via
		(at 367.098834 -229.272846)
		(size 0.4572)
		(drill 0.2032)
		(layers "F.Cu" "B.Cu")
		(net "H_CPU0_PM_FAST_WAKE_N")
	)
	(segment
		(start 373.960136 -228.134672)
		(end 373.949722 -228.140768)
		(width 0.0889)
		(layer "B.Cu")
		(net "H_CPU0_PM_FAST_WAKE_N")
	)
	(segment
		(start 367.16335 -228.642926)
		(end 367.098834 -229.272846)
		(width 0.0889)
		(layer "B.Cu")
		(net "H_CPU0_PM_FAST_WAKE_N")
	)
	(segment
		(start 385.733798 -195.85813)
		(end 390.681464 -200.805796)
		(width 0.12954)
		(layer "B.Cu")
		(net "H_CPU0_PM_FAST_WAKE_N")
	)
	(segment
		(start 390.681464 -200.805796)
		(end 390.681464 -223.942656)
		(width 0.12954)
		(layer "B.Cu")
		(net "H_CPU0_PM_FAST_WAKE_N")
	)
	(segment
		(start 373.020082 -228.134672)
		(end 373.00535 -228.143308)
		(width 0.0889)
		(layer "B.Cu")
		(net "H_CPU0_PM_FAST_WAKE_N")
	)
	(segment
		(start 367.19383 -228.45903)
		(end 367.19383 -228.474524)
		(width 0.0889)
		(layer "B.Cu")
		(net "H_CPU0_PM_FAST_WAKE_N")
	)
	(segment
		(start 388.97179 -225.65233)
		(end 388.97179 -225.885756)
		(width 0.12954)
		(layer "B.Cu")
		(net "H_CPU0_PM_FAST_WAKE_N")
	)
	(segment
		(start 380.80823 -192.12941)
		(end 381.69723 -193.01841)
		(width 0.12954)
		(layer "B.Cu")
		(net "H_CPU0_PM_FAST_WAKE_N")
	)
	(segment
		(start 378.658882 -228.134672)
		(end 378.64415 -228.143308)
		(width 0.0889)
		(layer "B.Cu")
		(net "H_CPU0_PM_FAST_WAKE_N")
	)
	(segment
		(start 368.321082 -228.134672)
		(end 368.30635 -228.143308)
		(width 0.0889)
		(layer "B.Cu")
		(net "H_CPU0_PM_FAST_WAKE_N")
	)
	(segment
		(start 380.80823 -191.22136)
		(end 380.80823 -192.12941)
		(width 0.12954)
		(layer "B.Cu")
		(net "H_CPU0_PM_FAST_WAKE_N")
	)
	(segment
		(start 382.418082 -228.134672)
		(end 382.407668 -228.140768)
		(width 0.0889)
		(layer "B.Cu")
		(net "H_CPU0_PM_FAST_WAKE_N")
	)
	(segment
		(start 374.899682 -228.134672)
		(end 374.889268 -228.140768)
		(width 0.0889)
		(layer "B.Cu")
		(net "H_CPU0_PM_FAST_WAKE_N")
	)
	(segment
		(start 384.932936 -228.044756)
		(end 383.47523 -228.044756)
		(width 0.0889)
		(layer "B.Cu")
		(net "H_CPU0_PM_FAST_WAKE_N")
	)
	(segment
		(start 388.97179 -225.885756)
		(end 386.695696 -228.16185)
		(width 0.12954)
		(layer "B.Cu")
		(net "H_CPU0_PM_FAST_WAKE_N")
	)
	(segment
		(start 385.245102 -228.16185)
		(end 384.932936 -228.044756)
		(width 0.0889)
		(layer "B.Cu")
		(net "H_CPU0_PM_FAST_WAKE_N")
	)
	(segment
		(start 371.140482 -228.134672)
		(end 371.12575 -228.143308)
		(width 0.0889)
		(layer "B.Cu")
		(net "H_CPU0_PM_FAST_WAKE_N")
	)
	(segment
		(start 377.719082 -228.134672)
		(end 377.70435 -228.143308)
		(width 0.0889)
		(layer "B.Cu")
		(net "H_CPU0_PM_FAST_WAKE_N")
	)
	(segment
		(start 380.538736 -228.134672)
		(end 380.528322 -228.140768)
		(width 0.0889)
		(layer "B.Cu")
		(net "H_CPU0_PM_FAST_WAKE_N")
	)
	(segment
		(start 384.53695 -195.85813)
		(end 385.733798 -195.85813)
		(width 0.12954)
		(layer "B.Cu")
		(net "H_CPU0_PM_FAST_WAKE_N")
	)
	(segment
		(start 379.598682 -228.134672)
		(end 379.58395 -228.143308)
		(width 0.0889)
		(layer "B.Cu")
		(net "H_CPU0_PM_FAST_WAKE_N")
	)
	(segment
		(start 369.260882 -228.134672)
		(end 369.24615 -228.143308)
		(width 0.0889)
		(layer "B.Cu")
		(net "H_CPU0_PM_FAST_WAKE_N")
	)
	(segment
		(start 367.381282 -228.134672)
		(end 367.372392 -228.139752)
		(width 0.0889)
		(layer "B.Cu")
		(net "H_CPU0_PM_FAST_WAKE_N")
	)
	(segment
		(start 381.69723 -193.01841)
		(end 384.53695 -195.85813)
		(width 0.12954)
		(layer "B.Cu")
		(net "H_CPU0_PM_FAST_WAKE_N")
	)
	(segment
		(start 372.080282 -228.134672)
		(end 372.06555 -228.143308)
		(width 0.0889)
		(layer "B.Cu")
		(net "H_CPU0_PM_FAST_WAKE_N")
	)
	(segment
		(start 383.358136 -228.134672)
		(end 383.347722 -228.140768)
		(width 0.0889)
		(layer "B.Cu")
		(net "H_CPU0_PM_FAST_WAKE_N")
	)
	(segment
		(start 386.695696 -228.16185)
		(end 385.245102 -228.16185)
		(width 0.12954)
		(layer "B.Cu")
		(net "H_CPU0_PM_FAST_WAKE_N")
	)
	(segment
		(start 390.681464 -223.942656)
		(end 388.97179 -225.65233)
		(width 0.12954)
		(layer "B.Cu")
		(net "H_CPU0_PM_FAST_WAKE_N")
	)
	(arc
		(start 375.839482 -228.134672)
		(mid 375.55678 -228.210414)
		(end 375.274078 -228.134672)
		(width 0.0889)
		(layer "B.Cu")
		(net "H_CPU0_PM_FAST_WAKE_N")
	)
	(arc
		(start 383.347722 -228.140768)
		(mid 383.06929 -228.210582)
		(end 382.792478 -228.134672)
		(width 0.0889)
		(layer "B.Cu")
		(net "H_CPU0_PM_FAST_WAKE_N")
	)
	(arc
		(start 374.334532 -228.134672)
		(mid 374.147334 -228.084529)
		(end 373.960136 -228.134672)
		(width 0.0889)
		(layer "B.Cu")
		(net "H_CPU0_PM_FAST_WAKE_N")
	)
	(arc
		(start 367.755678 -228.134672)
		(mid 367.56848 -228.084529)
		(end 367.381282 -228.134672)
		(width 0.0889)
		(layer "B.Cu")
		(net "H_CPU0_PM_FAST_WAKE_N")
	)
	(arc
		(start 369.24615 -228.143308)
		(mid 368.969709 -228.210474)
		(end 368.695478 -228.134672)
		(width 0.0889)
		(layer "B.Cu")
		(net "H_CPU0_PM_FAST_WAKE_N")
	)
	(arc
		(start 374.889268 -228.140768)
		(mid 374.61109 -228.21046)
		(end 374.334532 -228.134672)
		(width 0.0889)
		(layer "B.Cu")
		(net "H_CPU0_PM_FAST_WAKE_N")
	)
	(arc
		(start 378.093478 -228.134672)
		(mid 377.90628 -228.084529)
		(end 377.719082 -228.134672)
		(width 0.0889)
		(layer "B.Cu")
		(net "H_CPU0_PM_FAST_WAKE_N")
	)
	(arc
		(start 372.454678 -228.134672)
		(mid 372.26748 -228.084529)
		(end 372.080282 -228.134672)
		(width 0.0889)
		(layer "B.Cu")
		(net "H_CPU0_PM_FAST_WAKE_N")
	)
	(arc
		(start 381.478536 -228.134672)
		(mid 381.195834 -228.210414)
		(end 380.913132 -228.134672)
		(width 0.0889)
		(layer "B.Cu")
		(net "H_CPU0_PM_FAST_WAKE_N")
	)
	(arc
		(start 376.213878 -228.134672)
		(mid 376.02668 -228.084529)
		(end 375.839482 -228.134672)
		(width 0.0889)
		(layer "B.Cu")
		(net "H_CPU0_PM_FAST_WAKE_N")
	)
	(arc
		(start 368.30635 -228.143308)
		(mid 368.029909 -228.210474)
		(end 367.755678 -228.134672)
		(width 0.0889)
		(layer "B.Cu")
		(net "H_CPU0_PM_FAST_WAKE_N")
	)
	(arc
		(start 375.274078 -228.134672)
		(mid 375.08688 -228.084529)
		(end 374.899682 -228.134672)
		(width 0.0889)
		(layer "B.Cu")
		(net "H_CPU0_PM_FAST_WAKE_N")
	)
	(arc
		(start 379.973078 -228.134672)
		(mid 379.78588 -228.084529)
		(end 379.598682 -228.134672)
		(width 0.0889)
		(layer "B.Cu")
		(net "H_CPU0_PM_FAST_WAKE_N")
	)
	(arc
		(start 378.64415 -228.143308)
		(mid 378.367709 -228.210474)
		(end 378.093478 -228.134672)
		(width 0.0889)
		(layer "B.Cu")
		(net "H_CPU0_PM_FAST_WAKE_N")
	)
	(arc
		(start 370.200682 -228.134672)
		(mid 369.91798 -228.210414)
		(end 369.635278 -228.134672)
		(width 0.0889)
		(layer "B.Cu")
		(net "H_CPU0_PM_FAST_WAKE_N")
	)
	(arc
		(start 383.47523 -228.044756)
		(mid 383.419628 -228.093549)
		(end 383.358136 -228.134672)
		(width 0.0889)
		(layer "B.Cu")
		(net "H_CPU0_PM_FAST_WAKE_N")
	)
	(arc
		(start 371.514878 -228.134672)
		(mid 371.32768 -228.084529)
		(end 371.140482 -228.134672)
		(width 0.0889)
		(layer "B.Cu")
		(net "H_CPU0_PM_FAST_WAKE_N")
	)
	(arc
		(start 380.528322 -228.140768)
		(mid 380.24989 -228.210582)
		(end 379.973078 -228.134672)
		(width 0.0889)
		(layer "B.Cu")
		(net "H_CPU0_PM_FAST_WAKE_N")
	)
	(arc
		(start 382.792478 -228.134672)
		(mid 382.60528 -228.084529)
		(end 382.418082 -228.134672)
		(width 0.0889)
		(layer "B.Cu")
		(net "H_CPU0_PM_FAST_WAKE_N")
	)
	(arc
		(start 376.779282 -228.134672)
		(mid 376.49658 -228.210414)
		(end 376.213878 -228.134672)
		(width 0.0889)
		(layer "B.Cu")
		(net "H_CPU0_PM_FAST_WAKE_N")
	)
	(arc
		(start 380.913132 -228.134672)
		(mid 380.725934 -228.084529)
		(end 380.538736 -228.134672)
		(width 0.0889)
		(layer "B.Cu")
		(net "H_CPU0_PM_FAST_WAKE_N")
	)
	(arc
		(start 379.033278 -228.134672)
		(mid 378.84608 -228.084529)
		(end 378.658882 -228.134672)
		(width 0.0889)
		(layer "B.Cu")
		(net "H_CPU0_PM_FAST_WAKE_N")
	)
	(arc
		(start 381.852932 -228.134672)
		(mid 381.665734 -228.084529)
		(end 381.478536 -228.134672)
		(width 0.0889)
		(layer "B.Cu")
		(net "H_CPU0_PM_FAST_WAKE_N")
	)
	(arc
		(start 369.635278 -228.134672)
		(mid 369.44808 -228.084529)
		(end 369.260882 -228.134672)
		(width 0.0889)
		(layer "B.Cu")
		(net "H_CPU0_PM_FAST_WAKE_N")
	)
	(arc
		(start 382.407668 -228.140768)
		(mid 382.12949 -228.21046)
		(end 381.852932 -228.134672)
		(width 0.0889)
		(layer "B.Cu")
		(net "H_CPU0_PM_FAST_WAKE_N")
	)
	(arc
		(start 367.19383 -228.474524)
		(mid 367.185012 -228.559888)
		(end 367.16335 -228.642926)
		(width 0.0889)
		(layer "B.Cu")
		(net "H_CPU0_PM_FAST_WAKE_N")
	)
	(arc
		(start 373.00535 -228.143308)
		(mid 372.728909 -228.210474)
		(end 372.454678 -228.134672)
		(width 0.0889)
		(layer "B.Cu")
		(net "H_CPU0_PM_FAST_WAKE_N")
	)
	(arc
		(start 373.394478 -228.134672)
		(mid 373.20728 -228.084529)
		(end 373.020082 -228.134672)
		(width 0.0889)
		(layer "B.Cu")
		(net "H_CPU0_PM_FAST_WAKE_N")
	)
	(arc
		(start 377.70435 -228.143308)
		(mid 377.427909 -228.210474)
		(end 377.153678 -228.134672)
		(width 0.0889)
		(layer "B.Cu")
		(net "H_CPU0_PM_FAST_WAKE_N")
	)
	(arc
		(start 370.575078 -228.134672)
		(mid 370.38788 -228.084529)
		(end 370.200682 -228.134672)
		(width 0.0889)
		(layer "B.Cu")
		(net "H_CPU0_PM_FAST_WAKE_N")
	)
	(arc
		(start 368.695478 -228.134672)
		(mid 368.50828 -228.084529)
		(end 368.321082 -228.134672)
		(width 0.0889)
		(layer "B.Cu")
		(net "H_CPU0_PM_FAST_WAKE_N")
	)
	(arc
		(start 377.153678 -228.134672)
		(mid 376.96648 -228.084529)
		(end 376.779282 -228.134672)
		(width 0.0889)
		(layer "B.Cu")
		(net "H_CPU0_PM_FAST_WAKE_N")
	)
	(arc
		(start 367.372392 -228.139752)
		(mid 367.241478 -228.276112)
		(end 367.19383 -228.45903)
		(width 0.0889)
		(layer "B.Cu")
		(net "H_CPU0_PM_FAST_WAKE_N")
	)
	(arc
		(start 371.12575 -228.143308)
		(mid 370.849309 -228.210474)
		(end 370.575078 -228.134672)
		(width 0.0889)
		(layer "B.Cu")
		(net "H_CPU0_PM_FAST_WAKE_N")
	)
	(arc
		(start 372.06555 -228.143308)
		(mid 371.789109 -228.210474)
		(end 371.514878 -228.134672)
		(width 0.0889)
		(layer "B.Cu")
		(net "H_CPU0_PM_FAST_WAKE_N")
	)
	(arc
		(start 373.949722 -228.140768)
		(mid 373.67129 -228.210582)
		(end 373.394478 -228.134672)
		(width 0.0889)
		(layer "B.Cu")
		(net "H_CPU0_PM_FAST_WAKE_N")
	)
	(arc
		(start 379.58395 -228.143308)
		(mid 379.307509 -228.210474)
		(end 379.033278 -228.134672)
		(width 0.0889)
		(layer "B.Cu")
		(net "H_CPU0_PM_FAST_WAKE_N")
	)
	(segment
		(start 329.980036 -47.90567)
		(end 329.980036 -47.510446)
		(width 0.12954)
		(layer "F.Cu")
		(net "H_CPU0_PMSYNC_PCH_R2")
	)
	(segment
		(start 330.054712 -47.980346)
		(end 329.980036 -47.90567)
		(width 0.12954)
		(layer "F.Cu")
		(net "H_CPU0_PMSYNC_PCH_R2")
	)
	(segment
		(start 330.251816 -47.980346)
		(end 330.054712 -47.980346)
		(width 0.12954)
		(layer "F.Cu")
		(net "H_CPU0_PMSYNC_PCH_R2")
	)
	(via
		(at 327.963276 -47.980346)
		(size 0.6604)
		(drill 0.3302)
		(layers "F.Cu" "B.Cu")
		(net "H_CPU0_PMSYNC_PCH_R2")
	)
	(via
		(at 330.251816 -47.980346)
		(size 0.4572)
		(drill 0.2032)
		(layers "F.Cu" "B.Cu")
		(net "H_CPU0_PMSYNC_PCH_R2")
	)
	(segment
		(start 330.251816 -47.980346)
		(end 327.963276 -47.980346)
		(width 0.12954)
		(layer "B.Cu")
		(net "H_CPU0_PMSYNC_PCH_R2")
	)
	(segment
		(start 327.585324 -48.358298)
		(end 326.605392 -48.358298)
		(width 0.12954)
		(layer "B.Cu")
		(net "H_CPU0_PMSYNC_PCH_R2")
	)
	(segment
		(start 327.963276 -47.980346)
		(end 327.585324 -48.358298)
		(width 0.12954)
		(layer "B.Cu")
		(net "H_CPU0_PMSYNC_PCH_R2")
	)
	(via
		(at 401.273264 -201.664316)
		(size 0.6604)
		(drill 0.3302)
		(layers "F.Cu" "B.Cu")
		(net "H_CPU0_PMSYNC_PCH_R")
	)
	(via
		(at 301.409862 -76.769468)
		(size 0.508)
		(drill 0.254)
		(layers "F.Cu" "B.Cu")
		(net "H_CPU0_PMSYNC_PCH_R")
	)
	(via
		(at 296.46626 -133.838188)
		(size 0.508)
		(drill 0.254)
		(layers "F.Cu" "B.Cu")
		(net "H_CPU0_PMSYNC_PCH_R")
	)
	(via
		(at 316.00648 -42.535348)
		(size 0.508)
		(drill 0.254)
		(layers "F.Cu" "B.Cu")
		(net "H_CPU0_PMSYNC_PCH_R")
	)
	(segment
		(start 376.40006 -164.536374)
		(end 380.054358 -168.190672)
		(width 0.12954)
		(layer "B.Cu")
		(net "H_CPU0_PMSYNC_PCH_R")
	)
	(segment
		(start 316.00648 -42.865548)
		(end 316.89548 -43.754548)
		(width 0.12954)
		(layer "B.Cu")
		(net "H_CPU0_PMSYNC_PCH_R")
	)
	(segment
		(start 324.352412 -47.974758)
		(end 325.421752 -47.974758)
		(width 0.12954)
		(layer "B.Cu")
		(net "H_CPU0_PMSYNC_PCH_R")
	)
	(segment
		(start 402.292058 -202.68311)
		(end 402.292058 -228.26472)
		(width 0.12954)
		(layer "B.Cu")
		(net "H_CPU0_PMSYNC_PCH_R")
	)
	(segment
		(start 321.312286 -47.206408)
		(end 323.584062 -47.206408)
		(width 0.12954)
		(layer "B.Cu")
		(net "H_CPU0_PMSYNC_PCH_R")
	)
	(segment
		(start 380.054358 -172.27423)
		(end 390.096756 -182.316628)
		(width 0.12954)
		(layer "B.Cu")
		(net "H_CPU0_PMSYNC_PCH_R")
	)
	(segment
		(start 301.561246 -140.01496)
		(end 317.386208 -140.01496)
		(width 0.12954)
		(layer "B.Cu")
		(net "H_CPU0_PMSYNC_PCH_R")
	)
	(segment
		(start 391.238486 -184.025286)
		(end 394.306806 -191.431418)
		(width 0.12954)
		(layer "B.Cu")
		(net "H_CPU0_PMSYNC_PCH_R")
	)
	(segment
		(start 373.113554 -156.728668)
		(end 376.40006 -160.015174)
		(width 0.12954)
		(layer "B.Cu")
		(net "H_CPU0_PMSYNC_PCH_R")
	)
	(segment
		(start 400.237198 -200.62825)
		(end 401.273264 -201.664316)
		(width 0.12954)
		(layer "B.Cu")
		(net "H_CPU0_PMSYNC_PCH_R")
	)
	(segment
		(start 402.292058 -228.26472)
		(end 401.832318 -228.72446)
		(width 0.12954)
		(layer "B.Cu")
		(net "H_CPU0_PMSYNC_PCH_R")
	)
	(segment
		(start 332.100936 -146.109944)
		(end 344.04935 -146.109944)
		(width 0.12954)
		(layer "B.Cu")
		(net "H_CPU0_PMSYNC_PCH_R")
	)
	(segment
		(start 296.46626 -134.919974)
		(end 301.561246 -140.01496)
		(width 0.12954)
		(layer "B.Cu")
		(net "H_CPU0_PMSYNC_PCH_R")
	)
	(segment
		(start 344.04935 -146.109944)
		(end 354.668074 -156.728668)
		(width 0.12954)
		(layer "B.Cu")
		(net "H_CPU0_PMSYNC_PCH_R")
	)
	(segment
		(start 390.096756 -182.316628)
		(end 391.238486 -184.025286)
		(width 0.12954)
		(layer "B.Cu")
		(net "H_CPU0_PMSYNC_PCH_R")
	)
	(segment
		(start 316.00648 -42.535348)
		(end 316.00648 -42.865548)
		(width 0.12954)
		(layer "B.Cu")
		(net "H_CPU0_PMSYNC_PCH_R")
	)
	(segment
		(start 316.89548 -43.754548)
		(end 317.860426 -43.754548)
		(width 0.12954)
		(layer "B.Cu")
		(net "H_CPU0_PMSYNC_PCH_R")
	)
	(segment
		(start 400.237198 -197.36181)
		(end 400.237198 -200.62825)
		(width 0.12954)
		(layer "B.Cu")
		(net "H_CPU0_PMSYNC_PCH_R")
	)
	(segment
		(start 296.46626 -133.838188)
		(end 296.46626 -134.919974)
		(width 0.12954)
		(layer "B.Cu")
		(net "H_CPU0_PMSYNC_PCH_R")
	)
	(segment
		(start 394.306806 -191.431418)
		(end 400.237198 -197.36181)
		(width 0.12954)
		(layer "B.Cu")
		(net "H_CPU0_PMSYNC_PCH_R")
	)
	(segment
		(start 323.584062 -47.206408)
		(end 324.352412 -47.974758)
		(width 0.12954)
		(layer "B.Cu")
		(net "H_CPU0_PMSYNC_PCH_R")
	)
	(segment
		(start 317.386208 -140.01496)
		(end 332.100936 -146.109944)
		(width 0.12954)
		(layer "B.Cu")
		(net "H_CPU0_PMSYNC_PCH_R")
	)
	(segment
		(start 376.40006 -160.015174)
		(end 376.40006 -164.536374)
		(width 0.12954)
		(layer "B.Cu")
		(net "H_CPU0_PMSYNC_PCH_R")
	)
	(segment
		(start 317.860426 -43.754548)
		(end 321.312286 -47.206408)
		(width 0.12954)
		(layer "B.Cu")
		(net "H_CPU0_PMSYNC_PCH_R")
	)
	(segment
		(start 325.421752 -47.974758)
		(end 325.805292 -48.358298)
		(width 0.12954)
		(layer "B.Cu")
		(net "H_CPU0_PMSYNC_PCH_R")
	)
	(segment
		(start 354.668074 -156.728668)
		(end 373.113554 -156.728668)
		(width 0.12954)
		(layer "B.Cu")
		(net "H_CPU0_PMSYNC_PCH_R")
	)
	(segment
		(start 380.054358 -168.190672)
		(end 380.054358 -172.27423)
		(width 0.12954)
		(layer "B.Cu")
		(net "H_CPU0_PMSYNC_PCH_R")
	)
	(segment
		(start 401.273264 -201.664316)
		(end 402.292058 -202.68311)
		(width 0.12954)
		(layer "B.Cu")
		(net "H_CPU0_PMSYNC_PCH_R")
	)
	(segment
		(start 301.409862 -76.769468)
		(end 301.409862 -79.984346)
		(width 0.127)
		(layer "In2.Cu")
		(net "H_CPU0_PMSYNC_PCH_R")
	)
	(segment
		(start 301.409862 -79.984346)
		(end 296.46626 -84.927948)
		(width 0.127)
		(layer "In2.Cu")
		(net "H_CPU0_PMSYNC_PCH_R")
	)
	(segment
		(start 296.46626 -84.927948)
		(end 296.46626 -133.838188)
		(width 0.127)
		(layer "In2.Cu")
		(net "H_CPU0_PMSYNC_PCH_R")
	)
	(segment
		(start 307.574696 -49.643792)
		(end 307.574696 -52.950618)
		(width 0.127)
		(layer "In11.Cu")
		(net "H_CPU0_PMSYNC_PCH_R")
	)
	(segment
		(start 302.54448 -75.63612)
		(end 302.16094 -76.01966)
		(width 0.127)
		(layer "In11.Cu")
		(net "H_CPU0_PMSYNC_PCH_R")
	)
	(segment
		(start 310.77154 -46.446948)
		(end 307.574696 -49.643792)
		(width 0.127)
		(layer "In11.Cu")
		(net "H_CPU0_PMSYNC_PCH_R")
	)
	(segment
		(start 302.16094 -76.01966)
		(end 302.15967 -76.01966)
		(width 0.127)
		(layer "In11.Cu")
		(net "H_CPU0_PMSYNC_PCH_R")
	)
	(segment
		(start 307.574696 -52.950618)
		(end 304.5968 -55.928514)
		(width 0.127)
		(layer "In11.Cu")
		(net "H_CPU0_PMSYNC_PCH_R")
	)
	(segment
		(start 302.54448 -59.870848)
		(end 302.54448 -75.63612)
		(width 0.127)
		(layer "In11.Cu")
		(net "H_CPU0_PMSYNC_PCH_R")
	)
	(segment
		(start 304.5968 -55.928514)
		(end 304.5968 -57.818528)
		(width 0.127)
		(layer "In11.Cu")
		(net "H_CPU0_PMSYNC_PCH_R")
	)
	(segment
		(start 312.09488 -46.446948)
		(end 310.77154 -46.446948)
		(width 0.127)
		(layer "In11.Cu")
		(net "H_CPU0_PMSYNC_PCH_R")
	)
	(segment
		(start 316.00648 -42.535348)
		(end 312.09488 -46.446948)
		(width 0.127)
		(layer "In11.Cu")
		(net "H_CPU0_PMSYNC_PCH_R")
	)
	(segment
		(start 302.15967 -76.01966)
		(end 301.409862 -76.769468)
		(width 0.127)
		(layer "In11.Cu")
		(net "H_CPU0_PMSYNC_PCH_R")
	)
	(segment
		(start 304.5968 -57.818528)
		(end 302.54448 -59.870848)
		(width 0.127)
		(layer "In11.Cu")
		(net "H_CPU0_PMSYNC_PCH_R")
	)
	(segment
		(start 370.387626 -244.73662)
		(end 370.38788 -244.736366)
		(width 0.12954)
		(layer "F.Cu")
		(net "H_CPU0_PMSYNC_PCH")
	)
	(segment
		(start 370.388134 -245.27256)
		(end 370.387626 -244.73662)
		(width 0.12954)
		(layer "F.Cu")
		(net "H_CPU0_PMSYNC_PCH")
	)
	(via
		(at 390.03732 -240.806224)
		(size 0.6604)
		(drill 0.3302)
		(layers "F.Cu" "B.Cu")
		(net "H_CPU0_PMSYNC_PCH")
	)
	(via
		(at 370.38788 -244.736366)
		(size 0.4572)
		(drill 0.2032)
		(layers "F.Cu" "B.Cu")
		(net "H_CPU0_PMSYNC_PCH")
	)
	(segment
		(start 372.06555 -245.052342)
		(end 372.080282 -245.060978)
		(width 0.0889)
		(layer "B.Cu")
		(net "H_CPU0_PMSYNC_PCH")
	)
	(segment
		(start 385.9022 -241.58067)
		(end 386.676646 -240.806224)
		(width 0.12954)
		(layer "B.Cu")
		(net "H_CPU0_PMSYNC_PCH")
	)
	(segment
		(start 390.550654 -240.806224)
		(end 401.832318 -229.52456)
		(width 0.12954)
		(layer "B.Cu")
		(net "H_CPU0_PMSYNC_PCH")
	)
	(segment
		(start 377.70435 -245.052342)
		(end 377.719082 -245.060978)
		(width 0.0889)
		(layer "B.Cu")
		(net "H_CPU0_PMSYNC_PCH")
	)
	(segment
		(start 373.009922 -245.054882)
		(end 373.020336 -245.060978)
		(width 0.0889)
		(layer "B.Cu")
		(net "H_CPU0_PMSYNC_PCH")
	)
	(segment
		(start 370.85143 -244.920008)
		(end 371.032532 -244.997732)
		(width 0.0889)
		(layer "B.Cu")
		(net "H_CPU0_PMSYNC_PCH")
	)
	(segment
		(start 384.287268 -245.054882)
		(end 384.297682 -245.060978)
		(width 0.0889)
		(layer "B.Cu")
		(net "H_CPU0_PMSYNC_PCH")
	)
	(segment
		(start 376.76455 -245.052342)
		(end 376.779282 -245.060978)
		(width 0.0889)
		(layer "B.Cu")
		(net "H_CPU0_PMSYNC_PCH")
	)
	(segment
		(start 383.347722 -245.054882)
		(end 383.358136 -245.060978)
		(width 0.0889)
		(layer "B.Cu")
		(net "H_CPU0_PMSYNC_PCH")
	)
	(segment
		(start 381.468122 -245.054882)
		(end 381.478536 -245.060978)
		(width 0.0889)
		(layer "B.Cu")
		(net "H_CPU0_PMSYNC_PCH")
	)
	(segment
		(start 379.588522 -245.054882)
		(end 379.598936 -245.060978)
		(width 0.0889)
		(layer "B.Cu")
		(net "H_CPU0_PMSYNC_PCH")
	)
	(segment
		(start 374.889522 -245.054882)
		(end 374.899936 -245.060978)
		(width 0.0889)
		(layer "B.Cu")
		(net "H_CPU0_PMSYNC_PCH")
	)
	(segment
		(start 386.676646 -240.806224)
		(end 390.03732 -240.806224)
		(width 0.12954)
		(layer "B.Cu")
		(net "H_CPU0_PMSYNC_PCH")
	)
	(segment
		(start 370.38788 -244.736366)
		(end 370.85143 -244.920008)
		(width 0.0889)
		(layer "B.Cu")
		(net "H_CPU0_PMSYNC_PCH")
	)
	(segment
		(start 385.9022 -244.106192)
		(end 385.9022 -241.58067)
		(width 0.12954)
		(layer "B.Cu")
		(net "H_CPU0_PMSYNC_PCH")
	)
	(segment
		(start 382.407668 -245.054882)
		(end 382.418082 -245.060978)
		(width 0.0889)
		(layer "B.Cu")
		(net "H_CPU0_PMSYNC_PCH")
	)
	(segment
		(start 384.674618 -245.111778)
		(end 384.896614 -245.111778)
		(width 0.12954)
		(layer "B.Cu")
		(net "H_CPU0_PMSYNC_PCH")
	)
	(segment
		(start 384.485134 -245.111778)
		(end 384.674618 -245.111778)
		(width 0.0889)
		(layer "B.Cu")
		(net "H_CPU0_PMSYNC_PCH")
	)
	(segment
		(start 378.64415 -245.052342)
		(end 378.658882 -245.060978)
		(width 0.0889)
		(layer "B.Cu")
		(net "H_CPU0_PMSYNC_PCH")
	)
	(segment
		(start 390.03732 -240.806224)
		(end 390.550654 -240.806224)
		(width 0.12954)
		(layer "B.Cu")
		(net "H_CPU0_PMSYNC_PCH")
	)
	(segment
		(start 379.973332 -245.060978)
		(end 379.983746 -245.054882)
		(width 0.0889)
		(layer "B.Cu")
		(net "H_CPU0_PMSYNC_PCH")
	)
	(segment
		(start 375.274332 -245.060978)
		(end 375.284746 -245.054882)
		(width 0.0889)
		(layer "B.Cu")
		(net "H_CPU0_PMSYNC_PCH")
	)
	(segment
		(start 371.032532 -244.997732)
		(end 371.140482 -245.060978)
		(width 0.0889)
		(layer "B.Cu")
		(net "H_CPU0_PMSYNC_PCH")
	)
	(segment
		(start 373.394732 -245.060978)
		(end 373.405146 -245.054882)
		(width 0.0889)
		(layer "B.Cu")
		(net "H_CPU0_PMSYNC_PCH")
	)
	(segment
		(start 384.896614 -245.111778)
		(end 385.9022 -244.106192)
		(width 0.12954)
		(layer "B.Cu")
		(net "H_CPU0_PMSYNC_PCH")
	)
	(arc
		(start 371.140482 -245.060978)
		(mid 371.32768 -245.111121)
		(end 371.514878 -245.060978)
		(width 0.0889)
		(layer "B.Cu")
		(net "H_CPU0_PMSYNC_PCH")
	)
	(arc
		(start 375.284746 -245.054882)
		(mid 375.562924 -244.98519)
		(end 375.839482 -245.060978)
		(width 0.0889)
		(layer "B.Cu")
		(net "H_CPU0_PMSYNC_PCH")
	)
	(arc
		(start 374.899936 -245.060978)
		(mid 375.087134 -245.111121)
		(end 375.274332 -245.060978)
		(width 0.0889)
		(layer "B.Cu")
		(net "H_CPU0_PMSYNC_PCH")
	)
	(arc
		(start 380.538482 -245.060978)
		(mid 380.72568 -245.111121)
		(end 380.912878 -245.060978)
		(width 0.0889)
		(layer "B.Cu")
		(net "H_CPU0_PMSYNC_PCH")
	)
	(arc
		(start 372.080282 -245.060978)
		(mid 372.26748 -245.111121)
		(end 372.454678 -245.060978)
		(width 0.0889)
		(layer "B.Cu")
		(net "H_CPU0_PMSYNC_PCH")
	)
	(arc
		(start 381.852932 -245.060978)
		(mid 382.129491 -244.985269)
		(end 382.407668 -245.054882)
		(width 0.0889)
		(layer "B.Cu")
		(net "H_CPU0_PMSYNC_PCH")
	)
	(arc
		(start 378.093478 -245.060978)
		(mid 378.367707 -244.985053)
		(end 378.64415 -245.052342)
		(width 0.0889)
		(layer "B.Cu")
		(net "H_CPU0_PMSYNC_PCH")
	)
	(arc
		(start 377.153678 -245.060978)
		(mid 377.427907 -244.985053)
		(end 377.70435 -245.052342)
		(width 0.0889)
		(layer "B.Cu")
		(net "H_CPU0_PMSYNC_PCH")
	)
	(arc
		(start 371.514878 -245.060978)
		(mid 371.789107 -244.985053)
		(end 372.06555 -245.052342)
		(width 0.0889)
		(layer "B.Cu")
		(net "H_CPU0_PMSYNC_PCH")
	)
	(arc
		(start 378.658882 -245.060978)
		(mid 378.84608 -245.111121)
		(end 379.033278 -245.060978)
		(width 0.0889)
		(layer "B.Cu")
		(net "H_CPU0_PMSYNC_PCH")
	)
	(arc
		(start 373.405146 -245.054882)
		(mid 373.683324 -244.98519)
		(end 373.959882 -245.060978)
		(width 0.0889)
		(layer "B.Cu")
		(net "H_CPU0_PMSYNC_PCH")
	)
	(arc
		(start 381.478536 -245.060978)
		(mid 381.665734 -245.111121)
		(end 381.852932 -245.060978)
		(width 0.0889)
		(layer "B.Cu")
		(net "H_CPU0_PMSYNC_PCH")
	)
	(arc
		(start 373.959882 -245.060978)
		(mid 374.14708 -245.111121)
		(end 374.334278 -245.060978)
		(width 0.0889)
		(layer "B.Cu")
		(net "H_CPU0_PMSYNC_PCH")
	)
	(arc
		(start 382.792478 -245.060978)
		(mid 383.069291 -244.985142)
		(end 383.347722 -245.054882)
		(width 0.0889)
		(layer "B.Cu")
		(net "H_CPU0_PMSYNC_PCH")
	)
	(arc
		(start 373.020336 -245.060978)
		(mid 373.207534 -245.111121)
		(end 373.394732 -245.060978)
		(width 0.0889)
		(layer "B.Cu")
		(net "H_CPU0_PMSYNC_PCH")
	)
	(arc
		(start 379.598936 -245.060978)
		(mid 379.786134 -245.111121)
		(end 379.973332 -245.060978)
		(width 0.0889)
		(layer "B.Cu")
		(net "H_CPU0_PMSYNC_PCH")
	)
	(arc
		(start 374.334278 -245.060978)
		(mid 374.611091 -244.985142)
		(end 374.889522 -245.054882)
		(width 0.0889)
		(layer "B.Cu")
		(net "H_CPU0_PMSYNC_PCH")
	)
	(arc
		(start 382.418082 -245.060978)
		(mid 382.60528 -245.111121)
		(end 382.792478 -245.060978)
		(width 0.0889)
		(layer "B.Cu")
		(net "H_CPU0_PMSYNC_PCH")
	)
	(arc
		(start 372.454678 -245.060978)
		(mid 372.731491 -244.985142)
		(end 373.009922 -245.054882)
		(width 0.0889)
		(layer "B.Cu")
		(net "H_CPU0_PMSYNC_PCH")
	)
	(arc
		(start 380.912878 -245.060978)
		(mid 381.189691 -244.985142)
		(end 381.468122 -245.054882)
		(width 0.0889)
		(layer "B.Cu")
		(net "H_CPU0_PMSYNC_PCH")
	)
	(arc
		(start 377.719082 -245.060978)
		(mid 377.90628 -245.111121)
		(end 378.093478 -245.060978)
		(width 0.0889)
		(layer "B.Cu")
		(net "H_CPU0_PMSYNC_PCH")
	)
	(arc
		(start 379.033278 -245.060978)
		(mid 379.310091 -244.985142)
		(end 379.588522 -245.054882)
		(width 0.0889)
		(layer "B.Cu")
		(net "H_CPU0_PMSYNC_PCH")
	)
	(arc
		(start 384.297682 -245.060978)
		(mid 384.388061 -245.098733)
		(end 384.485134 -245.111778)
		(width 0.0889)
		(layer "B.Cu")
		(net "H_CPU0_PMSYNC_PCH")
	)
	(arc
		(start 383.358136 -245.060978)
		(mid 383.545334 -245.111121)
		(end 383.732532 -245.060978)
		(width 0.0889)
		(layer "B.Cu")
		(net "H_CPU0_PMSYNC_PCH")
	)
	(arc
		(start 376.779282 -245.060978)
		(mid 376.96648 -245.111121)
		(end 377.153678 -245.060978)
		(width 0.0889)
		(layer "B.Cu")
		(net "H_CPU0_PMSYNC_PCH")
	)
	(arc
		(start 379.983746 -245.054882)
		(mid 380.261924 -244.98519)
		(end 380.538482 -245.060978)
		(width 0.0889)
		(layer "B.Cu")
		(net "H_CPU0_PMSYNC_PCH")
	)
	(arc
		(start 375.839482 -245.060978)
		(mid 376.02668 -245.111121)
		(end 376.213878 -245.060978)
		(width 0.0889)
		(layer "B.Cu")
		(net "H_CPU0_PMSYNC_PCH")
	)
	(arc
		(start 376.213878 -245.060978)
		(mid 376.488107 -244.985053)
		(end 376.76455 -245.052342)
		(width 0.0889)
		(layer "B.Cu")
		(net "H_CPU0_PMSYNC_PCH")
	)
	(arc
		(start 383.732532 -245.060978)
		(mid 384.009091 -244.985269)
		(end 384.287268 -245.054882)
		(width 0.0889)
		(layer "B.Cu")
		(net "H_CPU0_PMSYNC_PCH")
	)
	(segment
		(start 366.62868 -233.877866)
		(end 366.62868 -233.34218)
		(width 0.12954)
		(layer "F.Cu")
		(net "H_CPU0_PMSYNC_CPU1_R")
	)
	(segment
		(start 366.628934 -233.87812)
		(end 366.62868 -233.877866)
		(width 0.12954)
		(layer "F.Cu")
		(net "H_CPU0_PMSYNC_CPU1_R")
	)
	(via
		(at 388.66699 -192.47866)
		(size 0.6604)
		(drill 0.3302)
		(layers "F.Cu" "B.Cu")
		(net "H_CPU0_PMSYNC_CPU1_R")
	)
	(via
		(at 366.62868 -233.34218)
		(size 0.4572)
		(drill 0.2032)
		(layers "F.Cu" "B.Cu")
		(net "H_CPU0_PMSYNC_CPU1_R")
	)
	(segment
		(start 394.116814 -228.128576)
		(end 389.015224 -233.230166)
		(width 0.12954)
		(layer "B.Cu")
		(net "H_CPU0_PMSYNC_CPU1_R")
	)
	(segment
		(start 385.500118 -233.696256)
		(end 384.651504 -232.847642)
		(width 0.12954)
		(layer "B.Cu")
		(net "H_CPU0_PMSYNC_CPU1_R")
	)
	(segment
		(start 373.020082 -233.017822)
		(end 373.00535 -233.026458)
		(width 0.0889)
		(layer "B.Cu")
		(net "H_CPU0_PMSYNC_CPU1_R")
	)
	(segment
		(start 387.890004 -233.696256)
		(end 385.500118 -233.696256)
		(width 0.12954)
		(layer "B.Cu")
		(net "H_CPU0_PMSYNC_CPU1_R")
	)
	(segment
		(start 379.598682 -233.017822)
		(end 379.58395 -233.026458)
		(width 0.0889)
		(layer "B.Cu")
		(net "H_CPU0_PMSYNC_CPU1_R")
	)
	(segment
		(start 388.66699 -191.98336)
		(end 388.66699 -192.47866)
		(width 0.12954)
		(layer "B.Cu")
		(net "H_CPU0_PMSYNC_CPU1_R")
	)
	(segment
		(start 387.90499 -191.22136)
		(end 388.66699 -191.98336)
		(width 0.12954)
		(layer "B.Cu")
		(net "H_CPU0_PMSYNC_CPU1_R")
	)
	(segment
		(start 372.080282 -233.017822)
		(end 372.06555 -233.026458)
		(width 0.0889)
		(layer "B.Cu")
		(net "H_CPU0_PMSYNC_CPU1_R")
	)
	(segment
		(start 367.226088 -233.07929)
		(end 366.62868 -233.34218)
		(width 0.0889)
		(layer "B.Cu")
		(net "H_CPU0_PMSYNC_CPU1_R")
	)
	(segment
		(start 376.779282 -233.017822)
		(end 376.76455 -233.026458)
		(width 0.0889)
		(layer "B.Cu")
		(net "H_CPU0_PMSYNC_CPU1_R")
	)
	(segment
		(start 373.960136 -233.017822)
		(end 373.949722 -233.023918)
		(width 0.0889)
		(layer "B.Cu")
		(net "H_CPU0_PMSYNC_CPU1_R")
	)
	(segment
		(start 367.381282 -233.017822)
		(end 367.36655 -233.026458)
		(width 0.0889)
		(layer "B.Cu")
		(net "H_CPU0_PMSYNC_CPU1_R")
	)
	(segment
		(start 388.66699 -193.351658)
		(end 394.116814 -198.801482)
		(width 0.12954)
		(layer "B.Cu")
		(net "H_CPU0_PMSYNC_CPU1_R")
	)
	(segment
		(start 384.651504 -232.847642)
		(end 384.326638 -232.847642)
		(width 0.12954)
		(layer "B.Cu")
		(net "H_CPU0_PMSYNC_CPU1_R")
	)
	(segment
		(start 394.116814 -198.801482)
		(end 394.116814 -228.128576)
		(width 0.12954)
		(layer "B.Cu")
		(net "H_CPU0_PMSYNC_CPU1_R")
	)
	(segment
		(start 389.015224 -233.230166)
		(end 387.890004 -233.696256)
		(width 0.12954)
		(layer "B.Cu")
		(net "H_CPU0_PMSYNC_CPU1_R")
	)
	(segment
		(start 368.332004 -233.011726)
		(end 368.321082 -233.018076)
		(width 0.0889)
		(layer "B.Cu")
		(net "H_CPU0_PMSYNC_CPU1_R")
	)
	(segment
		(start 388.66699 -192.47866)
		(end 388.66699 -193.351658)
		(width 0.12954)
		(layer "B.Cu")
		(net "H_CPU0_PMSYNC_CPU1_R")
	)
	(segment
		(start 380.927864 -233.026458)
		(end 380.913132 -233.017822)
		(width 0.0889)
		(layer "B.Cu")
		(net "H_CPU0_PMSYNC_CPU1_R")
	)
	(segment
		(start 378.658882 -233.017822)
		(end 378.64415 -233.026458)
		(width 0.0889)
		(layer "B.Cu")
		(net "H_CPU0_PMSYNC_CPU1_R")
	)
	(segment
		(start 380.538736 -233.017822)
		(end 380.528322 -233.023918)
		(width 0.0889)
		(layer "B.Cu")
		(net "H_CPU0_PMSYNC_CPU1_R")
	)
	(segment
		(start 377.719082 -233.017822)
		(end 377.70435 -233.026458)
		(width 0.0889)
		(layer "B.Cu")
		(net "H_CPU0_PMSYNC_CPU1_R")
	)
	(segment
		(start 374.344946 -233.023918)
		(end 374.334532 -233.017822)
		(width 0.0889)
		(layer "B.Cu")
		(net "H_CPU0_PMSYNC_CPU1_R")
	)
	(segment
		(start 375.839482 -233.017822)
		(end 375.82475 -233.026458)
		(width 0.0889)
		(layer "B.Cu")
		(net "H_CPU0_PMSYNC_CPU1_R")
	)
	(segment
		(start 384.326638 -232.847642)
		(end 383.555748 -232.847642)
		(width 0.0889)
		(layer "B.Cu")
		(net "H_CPU0_PMSYNC_CPU1_R")
	)
	(segment
		(start 371.140482 -233.017822)
		(end 371.12575 -233.026458)
		(width 0.0889)
		(layer "B.Cu")
		(net "H_CPU0_PMSYNC_CPU1_R")
	)
	(segment
		(start 383.555748 -232.847642)
		(end 383.47523 -232.92816)
		(width 0.0889)
		(layer "B.Cu")
		(net "H_CPU0_PMSYNC_CPU1_R")
	)
	(segment
		(start 367.755678 -233.018076)
		(end 367.744756 -233.011726)
		(width 0.0889)
		(layer "B.Cu")
		(net "H_CPU0_PMSYNC_CPU1_R")
	)
	(arc
		(start 380.913132 -233.017822)
		(mid 380.725934 -232.967679)
		(end 380.538736 -233.017822)
		(width 0.0889)
		(layer "B.Cu")
		(net "H_CPU0_PMSYNC_CPU1_R")
	)
	(arc
		(start 370.575078 -233.017822)
		(mid 370.38788 -232.967679)
		(end 370.200682 -233.017822)
		(width 0.0889)
		(layer "B.Cu")
		(net "H_CPU0_PMSYNC_CPU1_R")
	)
	(arc
		(start 369.635786 -233.017822)
		(mid 369.448588 -232.967679)
		(end 369.26139 -233.017822)
		(width 0.0889)
		(layer "B.Cu")
		(net "H_CPU0_PMSYNC_CPU1_R")
	)
	(arc
		(start 373.394478 -233.017822)
		(mid 373.20728 -232.967679)
		(end 373.020082 -233.017822)
		(width 0.0889)
		(layer "B.Cu")
		(net "H_CPU0_PMSYNC_CPU1_R")
	)
	(arc
		(start 379.033278 -233.017822)
		(mid 378.84608 -232.967679)
		(end 378.658882 -233.017822)
		(width 0.0889)
		(layer "B.Cu")
		(net "H_CPU0_PMSYNC_CPU1_R")
	)
	(arc
		(start 381.478536 -233.017822)
		(mid 381.204337 -233.093657)
		(end 380.927864 -233.026458)
		(width 0.0889)
		(layer "B.Cu")
		(net "H_CPU0_PMSYNC_CPU1_R")
	)
	(arc
		(start 376.213878 -233.017822)
		(mid 376.02668 -232.967679)
		(end 375.839482 -233.017822)
		(width 0.0889)
		(layer "B.Cu")
		(net "H_CPU0_PMSYNC_CPU1_R")
	)
	(arc
		(start 368.321082 -233.018076)
		(mid 368.03838 -233.093852)
		(end 367.755678 -233.018076)
		(width 0.0889)
		(layer "B.Cu")
		(net "H_CPU0_PMSYNC_CPU1_R")
	)
	(arc
		(start 380.528322 -233.023918)
		(mid 380.24989 -233.093764)
		(end 379.973078 -233.017822)
		(width 0.0889)
		(layer "B.Cu")
		(net "H_CPU0_PMSYNC_CPU1_R")
	)
	(arc
		(start 378.64415 -233.026458)
		(mid 378.367675 -233.093778)
		(end 378.093478 -233.017822)
		(width 0.0889)
		(layer "B.Cu")
		(net "H_CPU0_PMSYNC_CPU1_R")
	)
	(arc
		(start 381.852932 -233.017822)
		(mid 381.665734 -232.967679)
		(end 381.478536 -233.017822)
		(width 0.0889)
		(layer "B.Cu")
		(net "H_CPU0_PMSYNC_CPU1_R")
	)
	(arc
		(start 383.358136 -233.017822)
		(mid 383.075434 -233.093598)
		(end 382.792732 -233.017822)
		(width 0.0889)
		(layer "B.Cu")
		(net "H_CPU0_PMSYNC_CPU1_R")
	)
	(arc
		(start 382.792732 -233.017822)
		(mid 382.605534 -232.967679)
		(end 382.418336 -233.017822)
		(width 0.0889)
		(layer "B.Cu")
		(net "H_CPU0_PMSYNC_CPU1_R")
	)
	(arc
		(start 375.274078 -233.017822)
		(mid 375.08688 -232.967679)
		(end 374.899682 -233.017822)
		(width 0.0889)
		(layer "B.Cu")
		(net "H_CPU0_PMSYNC_CPU1_R")
	)
	(arc
		(start 375.82475 -233.026458)
		(mid 375.548275 -233.093778)
		(end 375.274078 -233.017822)
		(width 0.0889)
		(layer "B.Cu")
		(net "H_CPU0_PMSYNC_CPU1_R")
	)
	(arc
		(start 369.26139 -233.017822)
		(mid 368.978434 -233.093725)
		(end 368.695478 -233.017822)
		(width 0.0889)
		(layer "B.Cu")
		(net "H_CPU0_PMSYNC_CPU1_R")
	)
	(arc
		(start 367.36655 -233.026458)
		(mid 367.298078 -233.057549)
		(end 367.226088 -233.07929)
		(width 0.0889)
		(layer "B.Cu")
		(net "H_CPU0_PMSYNC_CPU1_R")
	)
	(arc
		(start 383.47523 -232.92816)
		(mid 383.419625 -232.976834)
		(end 383.358136 -233.017822)
		(width 0.0889)
		(layer "B.Cu")
		(net "H_CPU0_PMSYNC_CPU1_R")
	)
	(arc
		(start 371.12575 -233.026458)
		(mid 370.849275 -233.093778)
		(end 370.575078 -233.017822)
		(width 0.0889)
		(layer "B.Cu")
		(net "H_CPU0_PMSYNC_CPU1_R")
	)
	(arc
		(start 379.973078 -233.017822)
		(mid 379.78588 -232.967679)
		(end 379.598682 -233.017822)
		(width 0.0889)
		(layer "B.Cu")
		(net "H_CPU0_PMSYNC_CPU1_R")
	)
	(arc
		(start 373.949722 -233.023918)
		(mid 373.67129 -233.093764)
		(end 373.394478 -233.017822)
		(width 0.0889)
		(layer "B.Cu")
		(net "H_CPU0_PMSYNC_CPU1_R")
	)
	(arc
		(start 373.00535 -233.026458)
		(mid 372.728875 -233.093778)
		(end 372.454678 -233.017822)
		(width 0.0889)
		(layer "B.Cu")
		(net "H_CPU0_PMSYNC_CPU1_R")
	)
	(arc
		(start 374.334532 -233.017822)
		(mid 374.147334 -232.967679)
		(end 373.960136 -233.017822)
		(width 0.0889)
		(layer "B.Cu")
		(net "H_CPU0_PMSYNC_CPU1_R")
	)
	(arc
		(start 370.200682 -233.017822)
		(mid 369.918234 -233.093471)
		(end 369.635786 -233.017822)
		(width 0.0889)
		(layer "B.Cu")
		(net "H_CPU0_PMSYNC_CPU1_R")
	)
	(arc
		(start 378.093478 -233.017822)
		(mid 377.90628 -232.967679)
		(end 377.719082 -233.017822)
		(width 0.0889)
		(layer "B.Cu")
		(net "H_CPU0_PMSYNC_CPU1_R")
	)
	(arc
		(start 368.695478 -233.017822)
		(mid 368.514534 -232.967731)
		(end 368.332004 -233.011726)
		(width 0.0889)
		(layer "B.Cu")
		(net "H_CPU0_PMSYNC_CPU1_R")
	)
	(arc
		(start 379.58395 -233.026458)
		(mid 379.307475 -233.093778)
		(end 379.033278 -233.017822)
		(width 0.0889)
		(layer "B.Cu")
		(net "H_CPU0_PMSYNC_CPU1_R")
	)
	(arc
		(start 376.76455 -233.026458)
		(mid 376.488075 -233.093778)
		(end 376.213878 -233.017822)
		(width 0.0889)
		(layer "B.Cu")
		(net "H_CPU0_PMSYNC_CPU1_R")
	)
	(arc
		(start 372.06555 -233.026458)
		(mid 371.789075 -233.093778)
		(end 371.514878 -233.017822)
		(width 0.0889)
		(layer "B.Cu")
		(net "H_CPU0_PMSYNC_CPU1_R")
	)
	(arc
		(start 367.744756 -233.011726)
		(mid 367.562226 -232.967702)
		(end 367.381282 -233.017822)
		(width 0.0889)
		(layer "B.Cu")
		(net "H_CPU0_PMSYNC_CPU1_R")
	)
	(arc
		(start 371.514878 -233.017822)
		(mid 371.32768 -232.967679)
		(end 371.140482 -233.017822)
		(width 0.0889)
		(layer "B.Cu")
		(net "H_CPU0_PMSYNC_CPU1_R")
	)
	(arc
		(start 377.70435 -233.026458)
		(mid 377.427875 -233.093778)
		(end 377.153678 -233.017822)
		(width 0.0889)
		(layer "B.Cu")
		(net "H_CPU0_PMSYNC_CPU1_R")
	)
	(arc
		(start 382.418336 -233.017822)
		(mid 382.135634 -233.093598)
		(end 381.852932 -233.017822)
		(width 0.0889)
		(layer "B.Cu")
		(net "H_CPU0_PMSYNC_CPU1_R")
	)
	(arc
		(start 377.153678 -233.017822)
		(mid 376.96648 -232.967679)
		(end 376.779282 -233.017822)
		(width 0.0889)
		(layer "B.Cu")
		(net "H_CPU0_PMSYNC_CPU1_R")
	)
	(arc
		(start 372.454678 -233.017822)
		(mid 372.26748 -232.967679)
		(end 372.080282 -233.017822)
		(width 0.0889)
		(layer "B.Cu")
		(net "H_CPU0_PMSYNC_CPU1_R")
	)
	(arc
		(start 374.899682 -233.017822)
		(mid 374.623123 -233.093565)
		(end 374.344946 -233.023918)
		(width 0.0889)
		(layer "B.Cu")
		(net "H_CPU0_PMSYNC_CPU1_R")
	)
	(segment
		(start 121.508266 -244.736874)
		(end 121.508012 -244.73662)
		(width 0.12954)
		(layer "F.Cu")
		(net "H_CPU0_PMSYNC_CPU1")
	)
	(segment
		(start 121.508266 -245.27256)
		(end 121.508266 -244.736874)
		(width 0.12954)
		(layer "F.Cu")
		(net "H_CPU0_PMSYNC_CPU1")
	)
	(via
		(at 121.508012 -244.73662)
		(size 0.4572)
		(drill 0.2032)
		(layers "F.Cu" "B.Cu")
		(net "H_CPU0_PMSYNC_CPU1")
	)
	(via
		(at 141.401038 -239.64265)
		(size 0.6604)
		(drill 0.3302)
		(layers "F.Cu" "B.Cu")
		(net "H_CPU0_PMSYNC_CPU1")
	)
	(segment
		(start 126.168912 -243.738654)
		(end 126.168912 -244.188488)
		(width 0.12954)
		(layer "B.Cu")
		(net "H_CPU0_PMSYNC_CPU1")
	)
	(segment
		(start 126.168912 -244.188488)
		(end 126.031498 -244.325902)
		(width 0.12954)
		(layer "B.Cu")
		(net "H_CPU0_PMSYNC_CPU1")
	)
	(segment
		(start 152.302718 -239.64265)
		(end 141.401038 -239.64265)
		(width 0.12954)
		(layer "B.Cu")
		(net "H_CPU0_PMSYNC_CPU1")
	)
	(segment
		(start 137.5156 -240.708434)
		(end 137.397744 -240.993168)
		(width 0.12954)
		(layer "B.Cu")
		(net "H_CPU0_PMSYNC_CPU1")
	)
	(segment
		(start 155.392882 -238.728758)
		(end 153.21661 -238.728758)
		(width 0.12954)
		(layer "B.Cu")
		(net "H_CPU0_PMSYNC_CPU1")
	)
	(segment
		(start 136.085072 -243.237766)
		(end 135.808212 -243.514626)
		(width 0.12954)
		(layer "B.Cu")
		(net "H_CPU0_PMSYNC_CPU1")
	)
	(segment
		(start 137.713466 -240.250726)
		(end 137.5156 -240.448592)
		(width 0.12954)
		(layer "B.Cu")
		(net "H_CPU0_PMSYNC_CPU1")
	)
	(segment
		(start 121.91873 -244.325902)
		(end 121.508012 -244.73662)
		(width 0.12954)
		(layer "B.Cu")
		(net "H_CPU0_PMSYNC_CPU1")
	)
	(segment
		(start 135.808212 -243.514626)
		(end 126.39294 -243.514626)
		(width 0.12954)
		(layer "B.Cu")
		(net "H_CPU0_PMSYNC_CPU1")
	)
	(segment
		(start 137.397744 -240.993168)
		(end 137.026904 -241.547904)
		(width 0.12954)
		(layer "B.Cu")
		(net "H_CPU0_PMSYNC_CPU1")
	)
	(segment
		(start 141.401038 -239.64265)
		(end 140.792962 -240.250726)
		(width 0.12954)
		(layer "B.Cu")
		(net "H_CPU0_PMSYNC_CPU1")
	)
	(segment
		(start 137.5156 -240.448592)
		(end 137.5156 -240.708434)
		(width 0.12954)
		(layer "B.Cu")
		(net "H_CPU0_PMSYNC_CPU1")
	)
	(segment
		(start 140.792962 -240.250726)
		(end 137.713466 -240.250726)
		(width 0.12954)
		(layer "B.Cu")
		(net "H_CPU0_PMSYNC_CPU1")
	)
	(segment
		(start 126.031498 -244.325902)
		(end 121.91873 -244.325902)
		(width 0.12954)
		(layer "B.Cu")
		(net "H_CPU0_PMSYNC_CPU1")
	)
	(segment
		(start 137.026904 -241.547904)
		(end 136.085072 -242.489736)
		(width 0.12954)
		(layer "B.Cu")
		(net "H_CPU0_PMSYNC_CPU1")
	)
	(segment
		(start 126.39294 -243.514626)
		(end 126.168912 -243.738654)
		(width 0.12954)
		(layer "B.Cu")
		(net "H_CPU0_PMSYNC_CPU1")
	)
	(segment
		(start 136.085072 -242.489736)
		(end 136.085072 -243.237766)
		(width 0.12954)
		(layer "B.Cu")
		(net "H_CPU0_PMSYNC_CPU1")
	)
	(segment
		(start 153.21661 -238.728758)
		(end 152.302718 -239.64265)
		(width 0.12954)
		(layer "B.Cu")
		(net "H_CPU0_PMSYNC_CPU1")
	)
	(segment
		(start 369.91798 -245.550944)
		(end 369.918234 -245.55069)
		(width 0.12954)
		(layer "F.Cu")
		(net "H_CPU0_PMDOWN_PCH_R2")
	)
	(segment
		(start 369.91798 -246.08663)
		(end 369.91798 -245.550944)
		(width 0.12954)
		(layer "F.Cu")
		(net "H_CPU0_PMDOWN_PCH_R2")
	)
	(via
		(at 369.918234 -245.55069)
		(size 0.4572)
		(drill 0.2032)
		(layers "F.Cu" "B.Cu")
		(net "H_CPU0_PMDOWN_PCH_R2")
	)
	(via
		(at 391.932668 -241.67211)
		(size 0.6604)
		(drill 0.3302)
		(layers "F.Cu" "B.Cu")
		(net "H_CPU0_PMDOWN_PCH_R2")
	)
	(segment
		(start 391.932668 -241.67211)
		(end 400.804634 -232.800144)
		(width 0.12954)
		(layer "B.Cu")
		(net "H_CPU0_PMDOWN_PCH_R2")
	)
	(segment
		(start 380.058168 -245.232428)
		(end 380.068582 -245.226332)
		(width 0.0889)
		(layer "B.Cu")
		(net "H_CPU0_PMDOWN_PCH_R2")
	)
	(segment
		(start 385.353814 -245.470426)
		(end 386.321046 -244.503194)
		(width 0.12954)
		(layer "B.Cu")
		(net "H_CPU0_PMDOWN_PCH_R2")
	)
	(segment
		(start 373.864378 -245.226332)
		(end 373.874792 -245.232428)
		(width 0.0889)
		(layer "B.Cu")
		(net "H_CPU0_PMDOWN_PCH_R2")
	)
	(segment
		(start 380.442978 -245.226332)
		(end 380.453392 -245.232428)
		(width 0.0889)
		(layer "B.Cu")
		(net "H_CPU0_PMDOWN_PCH_R2")
	)
	(segment
		(start 375.359168 -245.232428)
		(end 375.369582 -245.226332)
		(width 0.0889)
		(layer "B.Cu")
		(net "H_CPU0_PMDOWN_PCH_R2")
	)
	(segment
		(start 386.321046 -242.228624)
		(end 386.877814 -241.671856)
		(width 0.12954)
		(layer "B.Cu")
		(net "H_CPU0_PMDOWN_PCH_R2")
	)
	(segment
		(start 389.345424 -241.67211)
		(end 391.932668 -241.67211)
		(width 0.12954)
		(layer "B.Cu")
		(net "H_CPU0_PMDOWN_PCH_R2")
	)
	(segment
		(start 377.623832 -245.226332)
		(end 377.638564 -245.234968)
		(width 0.0889)
		(layer "B.Cu")
		(net "H_CPU0_PMDOWN_PCH_R2")
	)
	(segment
		(start 375.743978 -245.226332)
		(end 375.754392 -245.232428)
		(width 0.0889)
		(layer "B.Cu")
		(net "H_CPU0_PMDOWN_PCH_R2")
	)
	(segment
		(start 378.563632 -245.226332)
		(end 378.578364 -245.234968)
		(width 0.0889)
		(layer "B.Cu")
		(net "H_CPU0_PMDOWN_PCH_R2")
	)
	(segment
		(start 376.684032 -245.226332)
		(end 376.698764 -245.234968)
		(width 0.0889)
		(layer "B.Cu")
		(net "H_CPU0_PMDOWN_PCH_R2")
	)
	(segment
		(start 400.804634 -232.800144)
		(end 400.804634 -232.375964)
		(width 0.12954)
		(layer "B.Cu")
		(net "H_CPU0_PMDOWN_PCH_R2")
	)
	(segment
		(start 371.045232 -245.226332)
		(end 371.059964 -245.234968)
		(width 0.0889)
		(layer "B.Cu")
		(net "H_CPU0_PMDOWN_PCH_R2")
	)
	(segment
		(start 384.280156 -245.285768)
		(end 384.464814 -245.470426)
		(width 0.0889)
		(layer "B.Cu")
		(net "H_CPU0_PMDOWN_PCH_R2")
	)
	(segment
		(start 369.918234 -245.55069)
		(end 370.579142 -245.269004)
		(width 0.0889)
		(layer "B.Cu")
		(net "H_CPU0_PMDOWN_PCH_R2")
	)
	(segment
		(start 400.804634 -232.375964)
		(end 401.832318 -231.34828)
		(width 0.12954)
		(layer "B.Cu")
		(net "H_CPU0_PMDOWN_PCH_R2")
	)
	(segment
		(start 386.877814 -241.671856)
		(end 389.34517 -241.671856)
		(width 0.12954)
		(layer "B.Cu")
		(net "H_CPU0_PMDOWN_PCH_R2")
	)
	(segment
		(start 371.985032 -245.226332)
		(end 371.999764 -245.234968)
		(width 0.0889)
		(layer "B.Cu")
		(net "H_CPU0_PMDOWN_PCH_R2")
	)
	(segment
		(start 386.321046 -244.503194)
		(end 386.321046 -242.228624)
		(width 0.12954)
		(layer "B.Cu")
		(net "H_CPU0_PMDOWN_PCH_R2")
	)
	(segment
		(start 373.479568 -245.232428)
		(end 373.489982 -245.226332)
		(width 0.0889)
		(layer "B.Cu")
		(net "H_CPU0_PMDOWN_PCH_R2")
	)
	(segment
		(start 389.34517 -241.671856)
		(end 389.345424 -241.67211)
		(width 0.12954)
		(layer "B.Cu")
		(net "H_CPU0_PMDOWN_PCH_R2")
	)
	(segment
		(start 384.700018 -245.470426)
		(end 385.353814 -245.470426)
		(width 0.12954)
		(layer "B.Cu")
		(net "H_CPU0_PMDOWN_PCH_R2")
	)
	(segment
		(start 384.464814 -245.470426)
		(end 384.700018 -245.470426)
		(width 0.0889)
		(layer "B.Cu")
		(net "H_CPU0_PMDOWN_PCH_R2")
	)
	(segment
		(start 382.322832 -245.226332)
		(end 382.337564 -245.234968)
		(width 0.0889)
		(layer "B.Cu")
		(net "H_CPU0_PMDOWN_PCH_R2")
	)
	(arc
		(start 371.059964 -245.234968)
		(mid 371.336405 -245.302134)
		(end 371.610636 -245.226332)
		(width 0.0889)
		(layer "B.Cu")
		(net "H_CPU0_PMDOWN_PCH_R2")
	)
	(arc
		(start 373.874792 -245.232428)
		(mid 374.153224 -245.302242)
		(end 374.430036 -245.226332)
		(width 0.0889)
		(layer "B.Cu")
		(net "H_CPU0_PMDOWN_PCH_R2")
	)
	(arc
		(start 371.999764 -245.234968)
		(mid 372.276205 -245.302134)
		(end 372.550436 -245.226332)
		(width 0.0889)
		(layer "B.Cu")
		(net "H_CPU0_PMDOWN_PCH_R2")
	)
	(arc
		(start 372.924832 -245.226332)
		(mid 373.201391 -245.302041)
		(end 373.479568 -245.232428)
		(width 0.0889)
		(layer "B.Cu")
		(net "H_CPU0_PMDOWN_PCH_R2")
	)
	(arc
		(start 379.503432 -245.226332)
		(mid 379.779991 -245.302041)
		(end 380.058168 -245.232428)
		(width 0.0889)
		(layer "B.Cu")
		(net "H_CPU0_PMDOWN_PCH_R2")
	)
	(arc
		(start 377.249436 -245.226332)
		(mid 377.436634 -245.176189)
		(end 377.623832 -245.226332)
		(width 0.0889)
		(layer "B.Cu")
		(net "H_CPU0_PMDOWN_PCH_R2")
	)
	(arc
		(start 376.309636 -245.226332)
		(mid 376.496834 -245.176189)
		(end 376.684032 -245.226332)
		(width 0.0889)
		(layer "B.Cu")
		(net "H_CPU0_PMDOWN_PCH_R2")
	)
	(arc
		(start 379.129036 -245.226332)
		(mid 379.316234 -245.176189)
		(end 379.503432 -245.226332)
		(width 0.0889)
		(layer "B.Cu")
		(net "H_CPU0_PMDOWN_PCH_R2")
	)
	(arc
		(start 382.337564 -245.234968)
		(mid 382.614005 -245.302134)
		(end 382.888236 -245.226332)
		(width 0.0889)
		(layer "B.Cu")
		(net "H_CPU0_PMDOWN_PCH_R2")
	)
	(arc
		(start 381.948436 -245.226332)
		(mid 382.135634 -245.176189)
		(end 382.322832 -245.226332)
		(width 0.0889)
		(layer "B.Cu")
		(net "H_CPU0_PMDOWN_PCH_R2")
	)
	(arc
		(start 371.610636 -245.226332)
		(mid 371.797834 -245.176189)
		(end 371.985032 -245.226332)
		(width 0.0889)
		(layer "B.Cu")
		(net "H_CPU0_PMDOWN_PCH_R2")
	)
	(arc
		(start 378.189236 -245.226332)
		(mid 378.376434 -245.176189)
		(end 378.563632 -245.226332)
		(width 0.0889)
		(layer "B.Cu")
		(net "H_CPU0_PMDOWN_PCH_R2")
	)
	(arc
		(start 383.262632 -245.226332)
		(mid 383.545334 -245.302074)
		(end 383.828036 -245.226332)
		(width 0.0889)
		(layer "B.Cu")
		(net "H_CPU0_PMDOWN_PCH_R2")
	)
	(arc
		(start 373.489982 -245.226332)
		(mid 373.67718 -245.176189)
		(end 373.864378 -245.226332)
		(width 0.0889)
		(layer "B.Cu")
		(net "H_CPU0_PMDOWN_PCH_R2")
	)
	(arc
		(start 381.383032 -245.226332)
		(mid 381.665734 -245.302074)
		(end 381.948436 -245.226332)
		(width 0.0889)
		(layer "B.Cu")
		(net "H_CPU0_PMDOWN_PCH_R2")
	)
	(arc
		(start 381.008636 -245.226332)
		(mid 381.195834 -245.176189)
		(end 381.383032 -245.226332)
		(width 0.0889)
		(layer "B.Cu")
		(net "H_CPU0_PMDOWN_PCH_R2")
	)
	(arc
		(start 380.453392 -245.232428)
		(mid 380.731824 -245.302242)
		(end 381.008636 -245.226332)
		(width 0.0889)
		(layer "B.Cu")
		(net "H_CPU0_PMDOWN_PCH_R2")
	)
	(arc
		(start 384.202432 -245.226332)
		(mid 384.243241 -245.253504)
		(end 384.280156 -245.285768)
		(width 0.0889)
		(layer "B.Cu")
		(net "H_CPU0_PMDOWN_PCH_R2")
	)
	(arc
		(start 374.430036 -245.226332)
		(mid 374.617234 -245.176189)
		(end 374.804432 -245.226332)
		(width 0.0889)
		(layer "B.Cu")
		(net "H_CPU0_PMDOWN_PCH_R2")
	)
	(arc
		(start 370.670836 -245.226332)
		(mid 370.858034 -245.176189)
		(end 371.045232 -245.226332)
		(width 0.0889)
		(layer "B.Cu")
		(net "H_CPU0_PMDOWN_PCH_R2")
	)
	(arc
		(start 374.804432 -245.226332)
		(mid 375.080991 -245.302041)
		(end 375.359168 -245.232428)
		(width 0.0889)
		(layer "B.Cu")
		(net "H_CPU0_PMDOWN_PCH_R2")
	)
	(arc
		(start 378.578364 -245.234968)
		(mid 378.854805 -245.302134)
		(end 379.129036 -245.226332)
		(width 0.0889)
		(layer "B.Cu")
		(net "H_CPU0_PMDOWN_PCH_R2")
	)
	(arc
		(start 375.754392 -245.232428)
		(mid 376.032824 -245.302242)
		(end 376.309636 -245.226332)
		(width 0.0889)
		(layer "B.Cu")
		(net "H_CPU0_PMDOWN_PCH_R2")
	)
	(arc
		(start 382.888236 -245.226332)
		(mid 383.075434 -245.176189)
		(end 383.262632 -245.226332)
		(width 0.0889)
		(layer "B.Cu")
		(net "H_CPU0_PMDOWN_PCH_R2")
	)
	(arc
		(start 370.579142 -245.269004)
		(mid 370.625948 -245.249728)
		(end 370.670836 -245.226332)
		(width 0.0889)
		(layer "B.Cu")
		(net "H_CPU0_PMDOWN_PCH_R2")
	)
	(arc
		(start 377.638564 -245.234968)
		(mid 377.915005 -245.302134)
		(end 378.189236 -245.226332)
		(width 0.0889)
		(layer "B.Cu")
		(net "H_CPU0_PMDOWN_PCH_R2")
	)
	(arc
		(start 376.698764 -245.234968)
		(mid 376.975205 -245.302134)
		(end 377.249436 -245.226332)
		(width 0.0889)
		(layer "B.Cu")
		(net "H_CPU0_PMDOWN_PCH_R2")
	)
	(arc
		(start 372.550436 -245.226332)
		(mid 372.737634 -245.176189)
		(end 372.924832 -245.226332)
		(width 0.0889)
		(layer "B.Cu")
		(net "H_CPU0_PMDOWN_PCH_R2")
	)
	(arc
		(start 380.068582 -245.226332)
		(mid 380.25578 -245.176189)
		(end 380.442978 -245.226332)
		(width 0.0889)
		(layer "B.Cu")
		(net "H_CPU0_PMDOWN_PCH_R2")
	)
	(arc
		(start 375.369582 -245.226332)
		(mid 375.55678 -245.176189)
		(end 375.743978 -245.226332)
		(width 0.0889)
		(layer "B.Cu")
		(net "H_CPU0_PMDOWN_PCH_R2")
	)
	(arc
		(start 383.828036 -245.226332)
		(mid 384.015234 -245.176189)
		(end 384.202432 -245.226332)
		(width 0.0889)
		(layer "B.Cu")
		(net "H_CPU0_PMDOWN_PCH_R2")
	)
	(segment
		(start 306.74183 -48.097948)
		(end 305.87188 -48.097948)
		(width 0.12954)
		(layer "F.Cu")
		(net "H_CPU0_PMDOWN_PCH_R")
	)
	(via
		(at 301.95774 -75.206352)
		(size 0.762)
		(drill 0.254)
		(layers "F.Cu" "B.Cu")
		(net "H_CPU0_PMDOWN_PCH_R")
	)
	(via
		(at 401.226528 -200.00214)
		(size 0.6604)
		(drill 0.3302)
		(layers "F.Cu" "B.Cu")
		(net "H_CPU0_PMDOWN_PCH_R")
	)
	(via
		(at 305.87188 -48.097948)
		(size 0.508)
		(drill 0.254)
		(layers "F.Cu" "B.Cu")
		(net "H_CPU0_PMDOWN_PCH_R")
	)
	(via
		(at 297.10126 -133.838188)
		(size 0.508)
		(drill 0.254)
		(layers "F.Cu" "B.Cu")
		(net "H_CPU0_PMDOWN_PCH_R")
	)
	(segment
		(start 380.696978 -168.254934)
		(end 380.696978 -172.22089)
		(width 0.12954)
		(layer "B.Cu")
		(net "H_CPU0_PMDOWN_PCH_R")
	)
	(segment
		(start 380.696978 -172.22089)
		(end 390.303766 -181.827678)
		(width 0.12954)
		(layer "B.Cu")
		(net "H_CPU0_PMDOWN_PCH_R")
	)
	(segment
		(start 402.675598 -230.325676)
		(end 402.453094 -230.54818)
		(width 0.12954)
		(layer "B.Cu")
		(net "H_CPU0_PMDOWN_PCH_R")
	)
	(segment
		(start 394.62964 -191.208152)
		(end 400.795998 -197.37451)
		(width 0.12954)
		(layer "B.Cu")
		(net "H_CPU0_PMDOWN_PCH_R")
	)
	(segment
		(start 402.453094 -230.54818)
		(end 401.832318 -230.54818)
		(width 0.12954)
		(layer "B.Cu")
		(net "H_CPU0_PMDOWN_PCH_R")
	)
	(segment
		(start 401.226528 -200.00214)
		(end 402.675598 -201.45121)
		(width 0.12954)
		(layer "B.Cu")
		(net "H_CPU0_PMDOWN_PCH_R")
	)
	(segment
		(start 354.86086 -156.263848)
		(end 373.30634 -156.263848)
		(width 0.12954)
		(layer "B.Cu")
		(net "H_CPU0_PMDOWN_PCH_R")
	)
	(segment
		(start 297.10126 -133.838188)
		(end 297.10126 -134.897368)
		(width 0.12954)
		(layer "B.Cu")
		(net "H_CPU0_PMDOWN_PCH_R")
	)
	(segment
		(start 402.675598 -201.45121)
		(end 402.675598 -230.325676)
		(width 0.12954)
		(layer "B.Cu")
		(net "H_CPU0_PMDOWN_PCH_R")
	)
	(segment
		(start 297.10126 -134.897368)
		(end 301.754032 -139.55014)
		(width 0.12954)
		(layer "B.Cu")
		(net "H_CPU0_PMDOWN_PCH_R")
	)
	(segment
		(start 373.30634 -156.263848)
		(end 376.86488 -159.822388)
		(width 0.12954)
		(layer "B.Cu")
		(net "H_CPU0_PMDOWN_PCH_R")
	)
	(segment
		(start 317.967868 -139.55014)
		(end 332.44409 -145.546318)
		(width 0.12954)
		(layer "B.Cu")
		(net "H_CPU0_PMDOWN_PCH_R")
	)
	(segment
		(start 400.795998 -197.37451)
		(end 400.795998 -199.57161)
		(width 0.12954)
		(layer "B.Cu")
		(net "H_CPU0_PMDOWN_PCH_R")
	)
	(segment
		(start 376.86488 -164.422836)
		(end 380.696978 -168.254934)
		(width 0.12954)
		(layer "B.Cu")
		(net "H_CPU0_PMDOWN_PCH_R")
	)
	(segment
		(start 390.303766 -181.827678)
		(end 391.461752 -183.56072)
		(width 0.12954)
		(layer "B.Cu")
		(net "H_CPU0_PMDOWN_PCH_R")
	)
	(segment
		(start 391.461752 -183.56072)
		(end 394.62964 -191.208152)
		(width 0.12954)
		(layer "B.Cu")
		(net "H_CPU0_PMDOWN_PCH_R")
	)
	(segment
		(start 344.14333 -145.546318)
		(end 354.86086 -156.263848)
		(width 0.12954)
		(layer "B.Cu")
		(net "H_CPU0_PMDOWN_PCH_R")
	)
	(segment
		(start 332.44409 -145.546318)
		(end 344.14333 -145.546318)
		(width 0.12954)
		(layer "B.Cu")
		(net "H_CPU0_PMDOWN_PCH_R")
	)
	(segment
		(start 301.754032 -139.55014)
		(end 317.967868 -139.55014)
		(width 0.12954)
		(layer "B.Cu")
		(net "H_CPU0_PMDOWN_PCH_R")
	)
	(segment
		(start 400.795998 -199.57161)
		(end 401.226528 -200.00214)
		(width 0.12954)
		(layer "B.Cu")
		(net "H_CPU0_PMDOWN_PCH_R")
	)
	(segment
		(start 376.86488 -159.822388)
		(end 376.86488 -164.422836)
		(width 0.12954)
		(layer "B.Cu")
		(net "H_CPU0_PMDOWN_PCH_R")
	)
	(segment
		(start 301.95774 -75.206352)
		(end 301.95774 -80.447388)
		(width 0.127)
		(layer "In2.Cu")
		(net "H_CPU0_PMDOWN_PCH_R")
	)
	(segment
		(start 297.10126 -85.303868)
		(end 297.10126 -133.838188)
		(width 0.127)
		(layer "In2.Cu")
		(net "H_CPU0_PMDOWN_PCH_R")
	)
	(segment
		(start 301.95774 -80.447388)
		(end 297.10126 -85.303868)
		(width 0.127)
		(layer "In2.Cu")
		(net "H_CPU0_PMDOWN_PCH_R")
	)
	(segment
		(start 304.44186 -51.478688)
		(end 304.44186 -53.243988)
		(width 0.127)
		(layer "In11.Cu")
		(net "H_CPU0_PMDOWN_PCH_R")
	)
	(segment
		(start 302.11268 -59.454288)
		(end 302.11268 -75.051412)
		(width 0.127)
		(layer "In11.Cu")
		(net "H_CPU0_PMDOWN_PCH_R")
	)
	(segment
		(start 305.26228 -50.658268)
		(end 304.44186 -51.478688)
		(width 0.127)
		(layer "In11.Cu")
		(net "H_CPU0_PMDOWN_PCH_R")
	)
	(segment
		(start 302.11268 -75.051412)
		(end 301.95774 -75.206352)
		(width 0.127)
		(layer "In11.Cu")
		(net "H_CPU0_PMDOWN_PCH_R")
	)
	(segment
		(start 304.038 -53.647848)
		(end 304.038 -57.528968)
		(width 0.127)
		(layer "In11.Cu")
		(net "H_CPU0_PMDOWN_PCH_R")
	)
	(segment
		(start 304.44186 -53.243988)
		(end 304.038 -53.647848)
		(width 0.127)
		(layer "In11.Cu")
		(net "H_CPU0_PMDOWN_PCH_R")
	)
	(segment
		(start 305.87188 -48.097948)
		(end 305.26228 -48.707548)
		(width 0.127)
		(layer "In11.Cu")
		(net "H_CPU0_PMDOWN_PCH_R")
	)
	(segment
		(start 304.038 -57.528968)
		(end 302.11268 -59.454288)
		(width 0.127)
		(layer "In11.Cu")
		(net "H_CPU0_PMDOWN_PCH_R")
	)
	(segment
		(start 305.26228 -48.707548)
		(end 305.26228 -50.658268)
		(width 0.127)
		(layer "In11.Cu")
		(net "H_CPU0_PMDOWN_PCH_R")
	)
	(segment
		(start 307.54193 -48.097948)
		(end 308.28488 -48.097948)
		(width 0.12954)
		(layer "F.Cu")
		(net "H_CPU0_PMDOWN_PCH")
	)
	(segment
		(start 329.165966 -47.980346)
		(end 329.437746 -47.510446)
		(width 0.12954)
		(layer "F.Cu")
		(net "H_CPU0_PMDOWN_PCH")
	)
	(via
		(at 320.522346 -44.360592)
		(size 0.508)
		(drill 0.254)
		(layers "F.Cu" "B.Cu")
		(net "H_CPU0_PMDOWN_PCH")
	)
	(via
		(at 329.437746 -47.510446)
		(size 0.4572)
		(drill 0.2032)
		(layers "F.Cu" "B.Cu")
		(net "H_CPU0_PMDOWN_PCH")
	)
	(via
		(at 308.28488 -48.097948)
		(size 0.508)
		(drill 0.254)
		(layers "F.Cu" "B.Cu")
		(net "H_CPU0_PMDOWN_PCH")
	)
	(segment
		(start 322.224146 -46.594268)
		(end 320.522346 -44.892468)
		(width 0.12954)
		(layer "B.Cu")
		(net "H_CPU0_PMDOWN_PCH")
	)
	(segment
		(start 323.6214 -46.594268)
		(end 322.224146 -46.594268)
		(width 0.12954)
		(layer "B.Cu")
		(net "H_CPU0_PMDOWN_PCH")
	)
	(segment
		(start 324.5104 -47.483268)
		(end 323.6214 -46.594268)
		(width 0.12954)
		(layer "B.Cu")
		(net "H_CPU0_PMDOWN_PCH")
	)
	(segment
		(start 327.994264 -47.135288)
		(end 327.987914 -47.141638)
		(width 0.0889)
		(layer "B.Cu")
		(net "H_CPU0_PMDOWN_PCH")
	)
	(segment
		(start 326.30745 -47.141638)
		(end 325.96582 -47.483268)
		(width 0.12954)
		(layer "B.Cu")
		(net "H_CPU0_PMDOWN_PCH")
	)
	(segment
		(start 328.779886 -47.135288)
		(end 327.994264 -47.135288)
		(width 0.0889)
		(layer "B.Cu")
		(net "H_CPU0_PMDOWN_PCH")
	)
	(segment
		(start 325.96582 -47.483268)
		(end 324.5104 -47.483268)
		(width 0.12954)
		(layer "B.Cu")
		(net "H_CPU0_PMDOWN_PCH")
	)
	(segment
		(start 327.987914 -47.141638)
		(end 326.30745 -47.141638)
		(width 0.12954)
		(layer "B.Cu")
		(net "H_CPU0_PMDOWN_PCH")
	)
	(segment
		(start 329.437746 -47.510446)
		(end 329.155044 -47.510446)
		(width 0.0889)
		(layer "B.Cu")
		(net "H_CPU0_PMDOWN_PCH")
	)
	(segment
		(start 329.155044 -47.510446)
		(end 328.779886 -47.135288)
		(width 0.0889)
		(layer "B.Cu")
		(net "H_CPU0_PMDOWN_PCH")
	)
	(segment
		(start 320.522346 -44.892468)
		(end 320.522346 -44.360592)
		(width 0.12954)
		(layer "B.Cu")
		(net "H_CPU0_PMDOWN_PCH")
	)
	(segment
		(start 311.96788 -46.726348)
		(end 310.16448 -46.726348)
		(width 0.127)
		(layer "In15.Cu")
		(net "H_CPU0_PMDOWN_PCH")
	)
	(segment
		(start 308.79288 -48.097948)
		(end 308.28488 -48.097948)
		(width 0.127)
		(layer "In15.Cu")
		(net "H_CPU0_PMDOWN_PCH")
	)
	(segment
		(start 310.16448 -46.726348)
		(end 308.79288 -48.097948)
		(width 0.127)
		(layer "In15.Cu")
		(net "H_CPU0_PMDOWN_PCH")
	)
	(segment
		(start 320.522346 -44.360592)
		(end 314.333636 -44.360592)
		(width 0.127)
		(layer "In15.Cu")
		(net "H_CPU0_PMDOWN_PCH")
	)
	(segment
		(start 314.333636 -44.360592)
		(end 311.96788 -46.726348)
		(width 0.127)
		(layer "In15.Cu")
		(net "H_CPU0_PMDOWN_PCH")
	)
	(via
		(at 159.52978 -193.103754)
		(size 0.6604)
		(drill 0.3302)
		(layers "F.Cu" "B.Cu")
		(net "H_CPU0_PMDOWN_CPU1_R1")
	)
	(via
		(at 344.47988 -147.792948)
		(size 0.508)
		(drill 0.254)
		(layers "F.Cu" "B.Cu")
		(net "H_CPU0_PMDOWN_CPU1_R1")
	)
	(via
		(at 158.368238 -190.05169)
		(size 0.508)
		(drill 0.254)
		(layers "F.Cu" "B.Cu")
		(net "H_CPU0_PMDOWN_CPU1_R1")
	)
	(via
		(at 136.54024 -151.917908)
		(size 0.508)
		(drill 0.254)
		(layers "F.Cu" "B.Cu")
		(net "H_CPU0_PMDOWN_CPU1_R1")
	)
	(segment
		(start 154.85618 -223.822768)
		(end 154.85618 -219.972128)
		(width 0.12954)
		(layer "B.Cu")
		(net "H_CPU0_PMDOWN_CPU1_R1")
	)
	(segment
		(start 394.043916 -191.799464)
		(end 399.3642 -197.119748)
		(width 0.12954)
		(layer "B.Cu")
		(net "H_CPU0_PMDOWN_CPU1_R1")
	)
	(segment
		(start 158.756858 -196.33057)
		(end 158.756858 -195.16217)
		(width 0.12954)
		(layer "B.Cu")
		(net "H_CPU0_PMDOWN_CPU1_R1")
	)
	(segment
		(start 155.03652 -219.791788)
		(end 155.03652 -200.625202)
		(width 0.12954)
		(layer "B.Cu")
		(net "H_CPU0_PMDOWN_CPU1_R1")
	)
	(segment
		(start 379.670818 -172.433488)
		(end 389.731504 -182.494174)
		(width 0.12954)
		(layer "B.Cu")
		(net "H_CPU0_PMDOWN_CPU1_R1")
	)
	(segment
		(start 154.26436 -224.414588)
		(end 154.85618 -223.822768)
		(width 0.12954)
		(layer "B.Cu")
		(net "H_CPU0_PMDOWN_CPU1_R1")
	)
	(segment
		(start 401.832318 -203.146406)
		(end 401.832318 -226.824032)
		(width 0.12954)
		(layer "B.Cu")
		(net "H_CPU0_PMDOWN_CPU1_R1")
	)
	(segment
		(start 159.52978 -191.213232)
		(end 158.368238 -190.05169)
		(width 0.12954)
		(layer "B.Cu")
		(net "H_CPU0_PMDOWN_CPU1_R1")
	)
	(segment
		(start 351.437448 -157.13329)
		(end 372.945914 -157.13329)
		(width 0.12954)
		(layer "B.Cu")
		(net "H_CPU0_PMDOWN_CPU1_R1")
	)
	(segment
		(start 372.945914 -157.13329)
		(end 375.995438 -160.182814)
		(width 0.12954)
		(layer "B.Cu")
		(net "H_CPU0_PMDOWN_CPU1_R1")
	)
	(segment
		(start 399.3642 -197.119748)
		(end 399.3642 -200.678288)
		(width 0.12954)
		(layer "B.Cu")
		(net "H_CPU0_PMDOWN_CPU1_R1")
	)
	(segment
		(start 390.934702 -184.294526)
		(end 394.043916 -191.799464)
		(width 0.12954)
		(layer "B.Cu")
		(net "H_CPU0_PMDOWN_CPU1_R1")
	)
	(segment
		(start 159.52978 -193.103754)
		(end 159.52978 -191.213232)
		(width 0.12954)
		(layer "B.Cu")
		(net "H_CPU0_PMDOWN_CPU1_R1")
	)
	(segment
		(start 399.3642 -200.678288)
		(end 401.832318 -203.146406)
		(width 0.12954)
		(layer "B.Cu")
		(net "H_CPU0_PMDOWN_CPU1_R1")
	)
	(segment
		(start 344.47988 -147.792948)
		(end 344.47988 -150.175722)
		(width 0.12954)
		(layer "B.Cu")
		(net "H_CPU0_PMDOWN_CPU1_R1")
	)
	(segment
		(start 159.52978 -194.389248)
		(end 159.52978 -193.103754)
		(width 0.12954)
		(layer "B.Cu")
		(net "H_CPU0_PMDOWN_CPU1_R1")
	)
	(segment
		(start 379.670818 -168.55821)
		(end 379.670818 -172.433488)
		(width 0.12954)
		(layer "B.Cu")
		(net "H_CPU0_PMDOWN_CPU1_R1")
	)
	(segment
		(start 155.03652 -200.625202)
		(end 158.302198 -197.359524)
		(width 0.12954)
		(layer "B.Cu")
		(net "H_CPU0_PMDOWN_CPU1_R1")
	)
	(segment
		(start 389.731504 -182.494174)
		(end 390.934702 -184.294526)
		(width 0.12954)
		(layer "B.Cu")
		(net "H_CPU0_PMDOWN_CPU1_R1")
	)
	(segment
		(start 158.302198 -197.359524)
		(end 158.302198 -196.78523)
		(width 0.12954)
		(layer "B.Cu")
		(net "H_CPU0_PMDOWN_CPU1_R1")
	)
	(segment
		(start 375.995438 -164.88283)
		(end 379.670818 -168.55821)
		(width 0.12954)
		(layer "B.Cu")
		(net "H_CPU0_PMDOWN_CPU1_R1")
	)
	(segment
		(start 158.302198 -196.78523)
		(end 158.756858 -196.33057)
		(width 0.12954)
		(layer "B.Cu")
		(net "H_CPU0_PMDOWN_CPU1_R1")
	)
	(segment
		(start 375.995438 -160.182814)
		(end 375.995438 -164.88283)
		(width 0.12954)
		(layer "B.Cu")
		(net "H_CPU0_PMDOWN_CPU1_R1")
	)
	(segment
		(start 344.47988 -150.175722)
		(end 351.437448 -157.13329)
		(width 0.12954)
		(layer "B.Cu")
		(net "H_CPU0_PMDOWN_CPU1_R1")
	)
	(segment
		(start 154.85618 -219.972128)
		(end 155.03652 -219.791788)
		(width 0.12954)
		(layer "B.Cu")
		(net "H_CPU0_PMDOWN_CPU1_R1")
	)
	(segment
		(start 158.756858 -195.16217)
		(end 159.52978 -194.389248)
		(width 0.12954)
		(layer "B.Cu")
		(net "H_CPU0_PMDOWN_CPU1_R1")
	)
	(segment
		(start 157.765496 -189.448948)
		(end 155.44038 -189.448948)
		(width 0.127)
		(layer "In2.Cu")
		(net "H_CPU0_PMDOWN_CPU1_R1")
	)
	(segment
		(start 154.38247 -188.391038)
		(end 154.38247 -184.305702)
		(width 0.127)
		(layer "In2.Cu")
		(net "H_CPU0_PMDOWN_CPU1_R1")
	)
	(segment
		(start 142.33144 -151.917908)
		(end 136.54024 -151.917908)
		(width 0.127)
		(layer "In2.Cu")
		(net "H_CPU0_PMDOWN_CPU1_R1")
	)
	(segment
		(start 155.44038 -189.448948)
		(end 154.38247 -188.391038)
		(width 0.127)
		(layer "In2.Cu")
		(net "H_CPU0_PMDOWN_CPU1_R1")
	)
	(segment
		(start 158.368238 -190.05169)
		(end 157.765496 -189.448948)
		(width 0.127)
		(layer "In2.Cu")
		(net "H_CPU0_PMDOWN_CPU1_R1")
	)
	(segment
		(start 143.547338 -173.47057)
		(end 143.547338 -153.133806)
		(width 0.127)
		(layer "In2.Cu")
		(net "H_CPU0_PMDOWN_CPU1_R1")
	)
	(segment
		(start 143.547338 -153.133806)
		(end 142.33144 -151.917908)
		(width 0.127)
		(layer "In2.Cu")
		(net "H_CPU0_PMDOWN_CPU1_R1")
	)
	(segment
		(start 154.38247 -184.305702)
		(end 143.547338 -173.47057)
		(width 0.127)
		(layer "In2.Cu")
		(net "H_CPU0_PMDOWN_CPU1_R1")
	)
	(segment
		(start 186.844432 -168.145968)
		(end 176.63922 -168.145968)
		(width 0.127)
		(layer "In13.Cu")
		(net "H_CPU0_PMDOWN_CPU1_R1")
	)
	(segment
		(start 273.2786 -149.316948)
		(end 271.70888 -149.316948)
		(width 0.127)
		(layer "In13.Cu")
		(net "H_CPU0_PMDOWN_CPU1_R1")
	)
	(segment
		(start 269.35938 -151.666448)
		(end 267.70838 -151.666448)
		(width 0.127)
		(layer "In13.Cu")
		(net "H_CPU0_PMDOWN_CPU1_R1")
	)
	(segment
		(start 267.35024 -154.061668)
		(end 264.05078 -157.361128)
		(width 0.127)
		(layer "In13.Cu")
		(net "H_CPU0_PMDOWN_CPU1_R1")
	)
	(segment
		(start 217.013028 -157.361128)
		(end 209.098388 -165.275768)
		(width 0.127)
		(layer "In13.Cu")
		(net "H_CPU0_PMDOWN_CPU1_R1")
	)
	(segment
		(start 271.70888 -149.316948)
		(end 269.35938 -151.666448)
		(width 0.127)
		(layer "In13.Cu")
		(net "H_CPU0_PMDOWN_CPU1_R1")
	)
	(segment
		(start 153.4795 -168.961308)
		(end 148.3487 -163.830508)
		(width 0.127)
		(layer "In13.Cu")
		(net "H_CPU0_PMDOWN_CPU1_R1")
	)
	(segment
		(start 209.098388 -165.275768)
		(end 189.714632 -165.275768)
		(width 0.127)
		(layer "In13.Cu")
		(net "H_CPU0_PMDOWN_CPU1_R1")
	)
	(segment
		(start 267.35024 -152.024588)
		(end 267.35024 -154.061668)
		(width 0.127)
		(layer "In13.Cu")
		(net "H_CPU0_PMDOWN_CPU1_R1")
	)
	(segment
		(start 267.70838 -151.666448)
		(end 267.35024 -152.024588)
		(width 0.127)
		(layer "In13.Cu")
		(net "H_CPU0_PMDOWN_CPU1_R1")
	)
	(segment
		(start 175.82388 -168.961308)
		(end 153.4795 -168.961308)
		(width 0.127)
		(layer "In13.Cu")
		(net "H_CPU0_PMDOWN_CPU1_R1")
	)
	(segment
		(start 274.8026 -147.792948)
		(end 273.2786 -149.316948)
		(width 0.127)
		(layer "In13.Cu")
		(net "H_CPU0_PMDOWN_CPU1_R1")
	)
	(segment
		(start 189.714632 -165.275768)
		(end 186.844432 -168.145968)
		(width 0.127)
		(layer "In13.Cu")
		(net "H_CPU0_PMDOWN_CPU1_R1")
	)
	(segment
		(start 264.05078 -157.361128)
		(end 217.013028 -157.361128)
		(width 0.127)
		(layer "In13.Cu")
		(net "H_CPU0_PMDOWN_CPU1_R1")
	)
	(segment
		(start 148.3487 -163.830508)
		(end 148.3487 -163.726368)
		(width 0.127)
		(layer "In13.Cu")
		(net "H_CPU0_PMDOWN_CPU1_R1")
	)
	(segment
		(start 344.47988 -147.792948)
		(end 274.8026 -147.792948)
		(width 0.127)
		(layer "In13.Cu")
		(net "H_CPU0_PMDOWN_CPU1_R1")
	)
	(segment
		(start 176.63922 -168.145968)
		(end 175.82388 -168.961308)
		(width 0.127)
		(layer "In13.Cu")
		(net "H_CPU0_PMDOWN_CPU1_R1")
	)
	(segment
		(start 148.3487 -163.726368)
		(end 136.54024 -151.917908)
		(width 0.127)
		(layer "In13.Cu")
		(net "H_CPU0_PMDOWN_CPU1_R1")
	)
	(segment
		(start 369.448334 -244.736874)
		(end 369.44808 -244.73662)
		(width 0.12954)
		(layer "F.Cu")
		(net "H_CPU0_PMDOWN_CPU1_R")
	)
	(segment
		(start 369.448334 -245.27256)
		(end 369.448334 -244.736874)
		(width 0.12954)
		(layer "F.Cu")
		(net "H_CPU0_PMDOWN_CPU1_R")
	)
	(via
		(at 392.428222 -237.868206)
		(size 0.6604)
		(drill 0.3302)
		(layers "F.Cu" "B.Cu")
		(net "H_CPU0_PMDOWN_CPU1_R")
	)
	(via
		(at 369.44808 -244.73662)
		(size 0.4572)
		(drill 0.2032)
		(layers "F.Cu" "B.Cu")
		(net "H_CPU0_PMDOWN_CPU1_R")
	)
	(segment
		(start 385.658614 -240.274856)
		(end 390.021572 -240.274856)
		(width 0.12954)
		(layer "B.Cu")
		(net "H_CPU0_PMDOWN_CPU1_R")
	)
	(segment
		(start 370.021612 -244.4496)
		(end 370.335556 -244.135656)
		(width 0.12954)
		(layer "B.Cu")
		(net "H_CPU0_PMDOWN_CPU1_R")
	)
	(segment
		(start 370.670074 -243.514626)
		(end 384.818382 -243.514626)
		(width 0.12954)
		(layer "B.Cu")
		(net "H_CPU0_PMDOWN_CPU1_R")
	)
	(segment
		(start 384.818382 -243.514626)
		(end 385.432046 -242.900962)
		(width 0.12954)
		(layer "B.Cu")
		(net "H_CPU0_PMDOWN_CPU1_R")
	)
	(segment
		(start 385.432046 -240.501424)
		(end 385.658614 -240.274856)
		(width 0.12954)
		(layer "B.Cu")
		(net "H_CPU0_PMDOWN_CPU1_R")
	)
	(segment
		(start 392.428222 -237.868206)
		(end 399.506948 -230.78948)
		(width 0.12954)
		(layer "B.Cu")
		(net "H_CPU0_PMDOWN_CPU1_R")
	)
	(segment
		(start 369.44808 -244.73662)
		(end 369.7351 -244.4496)
		(width 0.0889)
		(layer "B.Cu")
		(net "H_CPU0_PMDOWN_CPU1_R")
	)
	(segment
		(start 370.335556 -244.135656)
		(end 370.335556 -243.849144)
		(width 0.12954)
		(layer "B.Cu")
		(net "H_CPU0_PMDOWN_CPU1_R")
	)
	(segment
		(start 370.335556 -243.849144)
		(end 370.670074 -243.514626)
		(width 0.12954)
		(layer "B.Cu")
		(net "H_CPU0_PMDOWN_CPU1_R")
	)
	(segment
		(start 399.506948 -230.78948)
		(end 399.506948 -229.949502)
		(width 0.12954)
		(layer "B.Cu")
		(net "H_CPU0_PMDOWN_CPU1_R")
	)
	(segment
		(start 390.021572 -240.274856)
		(end 392.428222 -237.868206)
		(width 0.12954)
		(layer "B.Cu")
		(net "H_CPU0_PMDOWN_CPU1_R")
	)
	(segment
		(start 385.432046 -242.900962)
		(end 385.432046 -240.501424)
		(width 0.12954)
		(layer "B.Cu")
		(net "H_CPU0_PMDOWN_CPU1_R")
	)
	(segment
		(start 369.7351 -244.4496)
		(end 370.021612 -244.4496)
		(width 0.12954)
		(layer "B.Cu")
		(net "H_CPU0_PMDOWN_CPU1_R")
	)
	(segment
		(start 399.506948 -229.949502)
		(end 401.832318 -227.624132)
		(width 0.12954)
		(layer "B.Cu")
		(net "H_CPU0_PMDOWN_CPU1_R")
	)
	(segment
		(start 118.688612 -233.877866)
		(end 118.688612 -233.34218)
		(width 0.12954)
		(layer "F.Cu")
		(net "H_CPU0_PMDOWN_CPU1")
	)
	(segment
		(start 118.688866 -233.87812)
		(end 118.688612 -233.877866)
		(width 0.12954)
		(layer "F.Cu")
		(net "H_CPU0_PMDOWN_CPU1")
	)
	(via
		(at 118.688612 -233.34218)
		(size 0.4572)
		(drill 0.2032)
		(layers "F.Cu" "B.Cu")
		(net "H_CPU0_PMDOWN_CPU1")
	)
	(via
		(at 151.275288 -226.87026)
		(size 0.6604)
		(drill 0.3302)
		(layers "F.Cu" "B.Cu")
		(net "H_CPU0_PMDOWN_CPU1")
	)
	(segment
		(start 119.426482 -233.026458)
		(end 119.441214 -233.017822)
		(width 0.0889)
		(layer "B.Cu")
		(net "H_CPU0_PMDOWN_CPU1")
	)
	(segment
		(start 126.394464 -233.017822)
		(end 126.404878 -233.023918)
		(width 0.0889)
		(layer "B.Cu")
		(net "H_CPU0_PMDOWN_CPU1")
	)
	(segment
		(start 140.659358 -233.44759)
		(end 146.608038 -233.44759)
		(width 0.12954)
		(layer "B.Cu")
		(net "H_CPU0_PMDOWN_CPU1")
	)
	(segment
		(start 132.588254 -233.023918)
		(end 132.598668 -233.017822)
		(width 0.0889)
		(layer "B.Cu")
		(net "H_CPU0_PMDOWN_CPU1")
	)
	(segment
		(start 146.608038 -233.44759)
		(end 150.867618 -229.18801)
		(width 0.12954)
		(layer "B.Cu")
		(net "H_CPU0_PMDOWN_CPU1")
	)
	(segment
		(start 126.009654 -233.023918)
		(end 126.020068 -233.017822)
		(width 0.0889)
		(layer "B.Cu")
		(net "H_CPU0_PMDOWN_CPU1")
	)
	(segment
		(start 128.824482 -233.026458)
		(end 128.839214 -233.017822)
		(width 0.0889)
		(layer "B.Cu")
		(net "H_CPU0_PMDOWN_CPU1")
	)
	(segment
		(start 130.704082 -233.026458)
		(end 130.718814 -233.017822)
		(width 0.0889)
		(layer "B.Cu")
		(net "H_CPU0_PMDOWN_CPU1")
	)
	(segment
		(start 129.764282 -233.026458)
		(end 129.779014 -233.017822)
		(width 0.0889)
		(layer "B.Cu")
		(net "H_CPU0_PMDOWN_CPU1")
	)
	(segment
		(start 151.275288 -226.87026)
		(end 152.93086 -225.214688)
		(width 0.12954)
		(layer "B.Cu")
		(net "H_CPU0_PMDOWN_CPU1")
	)
	(segment
		(start 140.484098 -233.62285)
		(end 140.659358 -233.44759)
		(width 0.12954)
		(layer "B.Cu")
		(net "H_CPU0_PMDOWN_CPU1")
	)
	(segment
		(start 137.055352 -233.34091)
		(end 138.058398 -233.34091)
		(width 0.12954)
		(layer "B.Cu")
		(net "H_CPU0_PMDOWN_CPU1")
	)
	(segment
		(start 150.867618 -227.27793)
		(end 151.275288 -226.87026)
		(width 0.12954)
		(layer "B.Cu")
		(net "H_CPU0_PMDOWN_CPU1")
	)
	(segment
		(start 150.867618 -229.18801)
		(end 150.867618 -227.27793)
		(width 0.12954)
		(layer "B.Cu")
		(net "H_CPU0_PMDOWN_CPU1")
	)
	(segment
		(start 138.058398 -233.34091)
		(end 138.340338 -233.62285)
		(width 0.12954)
		(layer "B.Cu")
		(net "H_CPU0_PMDOWN_CPU1")
	)
	(segment
		(start 131.643882 -233.026458)
		(end 131.658614 -233.017822)
		(width 0.0889)
		(layer "B.Cu")
		(net "H_CPU0_PMDOWN_CPU1")
	)
	(segment
		(start 121.310654 -233.023918)
		(end 121.321068 -233.017822)
		(width 0.0889)
		(layer "B.Cu")
		(net "H_CPU0_PMDOWN_CPU1")
	)
	(segment
		(start 122.2502 -233.023918)
		(end 122.260614 -233.017822)
		(width 0.0889)
		(layer "B.Cu")
		(net "H_CPU0_PMDOWN_CPU1")
	)
	(segment
		(start 118.937024 -233.093768)
		(end 119.160798 -233.093768)
		(width 0.0889)
		(layer "B.Cu")
		(net "H_CPU0_PMDOWN_CPU1")
	)
	(segment
		(start 152.93086 -225.214688)
		(end 154.26436 -225.214688)
		(width 0.12954)
		(layer "B.Cu")
		(net "H_CPU0_PMDOWN_CPU1")
	)
	(segment
		(start 136.732264 -233.017822)
		(end 136.956292 -233.24185)
		(width 0.0889)
		(layer "B.Cu")
		(net "H_CPU0_PMDOWN_CPU1")
	)
	(segment
		(start 123.185682 -233.026458)
		(end 123.200414 -233.017822)
		(width 0.0889)
		(layer "B.Cu")
		(net "H_CPU0_PMDOWN_CPU1")
	)
	(segment
		(start 136.956292 -233.24185)
		(end 137.055352 -233.34091)
		(width 0.12954)
		(layer "B.Cu")
		(net "H_CPU0_PMDOWN_CPU1")
	)
	(segment
		(start 138.340338 -233.62285)
		(end 140.484098 -233.62285)
		(width 0.12954)
		(layer "B.Cu")
		(net "H_CPU0_PMDOWN_CPU1")
	)
	(segment
		(start 132.973064 -233.017822)
		(end 132.987796 -233.026458)
		(width 0.0889)
		(layer "B.Cu")
		(net "H_CPU0_PMDOWN_CPU1")
	)
	(segment
		(start 125.065282 -233.026458)
		(end 125.080014 -233.017822)
		(width 0.0889)
		(layer "B.Cu")
		(net "H_CPU0_PMDOWN_CPU1")
	)
	(segment
		(start 127.884682 -233.026458)
		(end 127.899414 -233.017822)
		(width 0.0889)
		(layer "B.Cu")
		(net "H_CPU0_PMDOWN_CPU1")
	)
	(segment
		(start 118.688612 -233.34218)
		(end 118.937024 -233.093768)
		(width 0.0889)
		(layer "B.Cu")
		(net "H_CPU0_PMDOWN_CPU1")
	)
	(segment
		(start 124.125482 -233.026458)
		(end 124.140214 -233.017822)
		(width 0.0889)
		(layer "B.Cu")
		(net "H_CPU0_PMDOWN_CPU1")
	)
	(arc
		(start 136.357868 -233.017822)
		(mid 136.545066 -232.967679)
		(end 136.732264 -233.017822)
		(width 0.0889)
		(layer "B.Cu")
		(net "H_CPU0_PMDOWN_CPU1")
	)
	(arc
		(start 126.020068 -233.017822)
		(mid 126.207266 -232.967679)
		(end 126.394464 -233.017822)
		(width 0.0889)
		(layer "B.Cu")
		(net "H_CPU0_PMDOWN_CPU1")
	)
	(arc
		(start 119.160798 -233.093768)
		(mid 119.297789 -233.076477)
		(end 119.426482 -233.026458)
		(width 0.0889)
		(layer "B.Cu")
		(net "H_CPU0_PMDOWN_CPU1")
	)
	(arc
		(start 135.418068 -233.017822)
		(mid 135.605266 -232.967679)
		(end 135.792464 -233.017822)
		(width 0.0889)
		(layer "B.Cu")
		(net "H_CPU0_PMDOWN_CPU1")
	)
	(arc
		(start 128.27381 -233.017822)
		(mid 128.548009 -233.093657)
		(end 128.824482 -233.026458)
		(width 0.0889)
		(layer "B.Cu")
		(net "H_CPU0_PMDOWN_CPU1")
	)
	(arc
		(start 124.51461 -233.017822)
		(mid 124.788809 -233.093657)
		(end 125.065282 -233.026458)
		(width 0.0889)
		(layer "B.Cu")
		(net "H_CPU0_PMDOWN_CPU1")
	)
	(arc
		(start 132.598668 -233.017822)
		(mid 132.785866 -232.967679)
		(end 132.973064 -233.017822)
		(width 0.0889)
		(layer "B.Cu")
		(net "H_CPU0_PMDOWN_CPU1")
	)
	(arc
		(start 123.57481 -233.017822)
		(mid 123.849009 -233.093657)
		(end 124.125482 -233.026458)
		(width 0.0889)
		(layer "B.Cu")
		(net "H_CPU0_PMDOWN_CPU1")
	)
	(arc
		(start 125.080014 -233.017822)
		(mid 125.267212 -232.967679)
		(end 125.45441 -233.017822)
		(width 0.0889)
		(layer "B.Cu")
		(net "H_CPU0_PMDOWN_CPU1")
	)
	(arc
		(start 133.538468 -233.017822)
		(mid 133.725666 -232.967679)
		(end 133.912864 -233.017822)
		(width 0.0889)
		(layer "B.Cu")
		(net "H_CPU0_PMDOWN_CPU1")
	)
	(arc
		(start 126.404878 -233.023918)
		(mid 126.683056 -233.093641)
		(end 126.959614 -233.017822)
		(width 0.0889)
		(layer "B.Cu")
		(net "H_CPU0_PMDOWN_CPU1")
	)
	(arc
		(start 130.15341 -233.017822)
		(mid 130.427609 -233.093657)
		(end 130.704082 -233.026458)
		(width 0.0889)
		(layer "B.Cu")
		(net "H_CPU0_PMDOWN_CPU1")
	)
	(arc
		(start 121.321068 -233.017822)
		(mid 121.508266 -232.967679)
		(end 121.695464 -233.017822)
		(width 0.0889)
		(layer "B.Cu")
		(net "H_CPU0_PMDOWN_CPU1")
	)
	(arc
		(start 127.33401 -233.017822)
		(mid 127.608209 -233.093657)
		(end 127.884682 -233.026458)
		(width 0.0889)
		(layer "B.Cu")
		(net "H_CPU0_PMDOWN_CPU1")
	)
	(arc
		(start 122.63501 -233.017822)
		(mid 122.909209 -233.093657)
		(end 123.185682 -233.026458)
		(width 0.0889)
		(layer "B.Cu")
		(net "H_CPU0_PMDOWN_CPU1")
	)
	(arc
		(start 126.959614 -233.017822)
		(mid 127.146812 -232.967679)
		(end 127.33401 -233.017822)
		(width 0.0889)
		(layer "B.Cu")
		(net "H_CPU0_PMDOWN_CPU1")
	)
	(arc
		(start 121.695464 -233.017822)
		(mid 121.972023 -233.093565)
		(end 122.2502 -233.023918)
		(width 0.0889)
		(layer "B.Cu")
		(net "H_CPU0_PMDOWN_CPU1")
	)
	(arc
		(start 122.260614 -233.017822)
		(mid 122.447812 -232.967679)
		(end 122.63501 -233.017822)
		(width 0.0889)
		(layer "B.Cu")
		(net "H_CPU0_PMDOWN_CPU1")
	)
	(arc
		(start 119.81561 -233.017822)
		(mid 120.098312 -233.093598)
		(end 120.381014 -233.017822)
		(width 0.0889)
		(layer "B.Cu")
		(net "H_CPU0_PMDOWN_CPU1")
	)
	(arc
		(start 128.839214 -233.017822)
		(mid 129.026412 -232.967679)
		(end 129.21361 -233.017822)
		(width 0.0889)
		(layer "B.Cu")
		(net "H_CPU0_PMDOWN_CPU1")
	)
	(arc
		(start 123.200414 -233.017822)
		(mid 123.387612 -232.967679)
		(end 123.57481 -233.017822)
		(width 0.0889)
		(layer "B.Cu")
		(net "H_CPU0_PMDOWN_CPU1")
	)
	(arc
		(start 119.441214 -233.017822)
		(mid 119.628412 -232.967679)
		(end 119.81561 -233.017822)
		(width 0.0889)
		(layer "B.Cu")
		(net "H_CPU0_PMDOWN_CPU1")
	)
	(arc
		(start 134.852664 -233.017822)
		(mid 135.135366 -233.093598)
		(end 135.418068 -233.017822)
		(width 0.0889)
		(layer "B.Cu")
		(net "H_CPU0_PMDOWN_CPU1")
	)
	(arc
		(start 125.45441 -233.017822)
		(mid 125.731223 -233.093692)
		(end 126.009654 -233.023918)
		(width 0.0889)
		(layer "B.Cu")
		(net "H_CPU0_PMDOWN_CPU1")
	)
	(arc
		(start 127.899414 -233.017822)
		(mid 128.086612 -232.967679)
		(end 128.27381 -233.017822)
		(width 0.0889)
		(layer "B.Cu")
		(net "H_CPU0_PMDOWN_CPU1")
	)
	(arc
		(start 132.03301 -233.017822)
		(mid 132.309823 -233.093692)
		(end 132.588254 -233.023918)
		(width 0.0889)
		(layer "B.Cu")
		(net "H_CPU0_PMDOWN_CPU1")
	)
	(arc
		(start 132.987796 -233.026458)
		(mid 133.264271 -233.093778)
		(end 133.538468 -233.017822)
		(width 0.0889)
		(layer "B.Cu")
		(net "H_CPU0_PMDOWN_CPU1")
	)
	(arc
		(start 129.779014 -233.017822)
		(mid 129.966212 -232.967679)
		(end 130.15341 -233.017822)
		(width 0.0889)
		(layer "B.Cu")
		(net "H_CPU0_PMDOWN_CPU1")
	)
	(arc
		(start 130.718814 -233.017822)
		(mid 130.906012 -232.967679)
		(end 131.09321 -233.017822)
		(width 0.0889)
		(layer "B.Cu")
		(net "H_CPU0_PMDOWN_CPU1")
	)
	(arc
		(start 131.658614 -233.017822)
		(mid 131.845812 -232.967679)
		(end 132.03301 -233.017822)
		(width 0.0889)
		(layer "B.Cu")
		(net "H_CPU0_PMDOWN_CPU1")
	)
	(arc
		(start 120.381014 -233.017822)
		(mid 120.568212 -232.967679)
		(end 120.75541 -233.017822)
		(width 0.0889)
		(layer "B.Cu")
		(net "H_CPU0_PMDOWN_CPU1")
	)
	(arc
		(start 134.478268 -233.017822)
		(mid 134.665466 -232.967679)
		(end 134.852664 -233.017822)
		(width 0.0889)
		(layer "B.Cu")
		(net "H_CPU0_PMDOWN_CPU1")
	)
	(arc
		(start 124.140214 -233.017822)
		(mid 124.327412 -232.967679)
		(end 124.51461 -233.017822)
		(width 0.0889)
		(layer "B.Cu")
		(net "H_CPU0_PMDOWN_CPU1")
	)
	(arc
		(start 133.912864 -233.017822)
		(mid 134.195566 -233.093598)
		(end 134.478268 -233.017822)
		(width 0.0889)
		(layer "B.Cu")
		(net "H_CPU0_PMDOWN_CPU1")
	)
	(arc
		(start 120.75541 -233.017822)
		(mid 121.032223 -233.093692)
		(end 121.310654 -233.023918)
		(width 0.0889)
		(layer "B.Cu")
		(net "H_CPU0_PMDOWN_CPU1")
	)
	(arc
		(start 131.09321 -233.017822)
		(mid 131.367409 -233.093657)
		(end 131.643882 -233.026458)
		(width 0.0889)
		(layer "B.Cu")
		(net "H_CPU0_PMDOWN_CPU1")
	)
	(arc
		(start 129.21361 -233.017822)
		(mid 129.487809 -233.093657)
		(end 129.764282 -233.026458)
		(width 0.0889)
		(layer "B.Cu")
		(net "H_CPU0_PMDOWN_CPU1")
	)
	(arc
		(start 135.792464 -233.017822)
		(mid 136.075166 -233.093598)
		(end 136.357868 -233.017822)
		(width 0.0889)
		(layer "B.Cu")
		(net "H_CPU0_PMDOWN_CPU1")
	)
	(segment
		(start 350.182434 -228.180646)
		(end 350.182434 -227.64496)
		(width 0.12954)
		(layer "F.Cu")
		(net "H_CPU0_NMI_LVC1_N")
	)
	(segment
		(start 350.18218 -228.1809)
		(end 350.182434 -228.180646)
		(width 0.12954)
		(layer "F.Cu")
		(net "H_CPU0_NMI_LVC1_N")
	)
	(via
		(at 350.182434 -227.64496)
		(size 0.4572)
		(drill 0.2032)
		(layers "F.Cu" "B.Cu")
		(net "H_CPU0_NMI_LVC1_N")
	)
	(via
		(at 320.448178 -216.84361)
		(size 0.6604)
		(drill 0.3302)
		(layers "F.Cu" "B.Cu")
		(net "H_CPU0_NMI_LVC1_N")
	)
	(segment
		(start 350.02597 -227.915978)
		(end 349.936816 -227.939854)
		(width 0.0889)
		(layer "B.Cu")
		(net "H_CPU0_NMI_LVC1_N")
	)
	(segment
		(start 321.16268 -190.340742)
		(end 319.235328 -188.41339)
		(width 0.12954)
		(layer "B.Cu")
		(net "H_CPU0_NMI_LVC1_N")
	)
	(segment
		(start 350.182434 -227.64496)
		(end 350.02597 -227.915978)
		(width 0.0889)
		(layer "B.Cu")
		(net "H_CPU0_NMI_LVC1_N")
	)
	(segment
		(start 327.72731 -226.68103)
		(end 320.448178 -219.401898)
		(width 0.12954)
		(layer "B.Cu")
		(net "H_CPU0_NMI_LVC1_N")
	)
	(segment
		(start 340.986364 -227.960682)
		(end 340.971632 -227.969318)
		(width 0.0889)
		(layer "B.Cu")
		(net "H_CPU0_NMI_LVC1_N")
	)
	(segment
		(start 337.227164 -227.960682)
		(end 337.212432 -227.969318)
		(width 0.0889)
		(layer "B.Cu")
		(net "H_CPU0_NMI_LVC1_N")
	)
	(segment
		(start 319.235328 -188.41339)
		(end 319.073022 -188.251084)
		(width 0.12954)
		(layer "B.Cu")
		(net "H_CPU0_NMI_LVC1_N")
	)
	(segment
		(start 320.448178 -216.84361)
		(end 321.16268 -216.129108)
		(width 0.12954)
		(layer "B.Cu")
		(net "H_CPU0_NMI_LVC1_N")
	)
	(segment
		(start 340.041992 -227.963222)
		(end 340.031578 -227.969318)
		(width 0.0889)
		(layer "B.Cu")
		(net "H_CPU0_NMI_LVC1_N")
	)
	(segment
		(start 344.745564 -227.960682)
		(end 344.730832 -227.969318)
		(width 0.0889)
		(layer "B.Cu")
		(net "H_CPU0_NMI_LVC1_N")
	)
	(segment
		(start 339.657182 -227.969318)
		(end 339.646768 -227.963222)
		(width 0.0889)
		(layer "B.Cu")
		(net "H_CPU0_NMI_LVC1_N")
	)
	(segment
		(start 321.16268 -216.129108)
		(end 321.16268 -190.340742)
		(width 0.12954)
		(layer "B.Cu")
		(net "H_CPU0_NMI_LVC1_N")
	)
	(segment
		(start 348.504764 -227.960682)
		(end 348.490032 -227.969318)
		(width 0.0889)
		(layer "B.Cu")
		(net "H_CPU0_NMI_LVC1_N")
	)
	(segment
		(start 341.926164 -227.960682)
		(end 341.911432 -227.969318)
		(width 0.0889)
		(layer "B.Cu")
		(net "H_CPU0_NMI_LVC1_N")
	)
	(segment
		(start 346.620846 -227.963222)
		(end 346.610432 -227.969318)
		(width 0.0889)
		(layer "B.Cu")
		(net "H_CPU0_NMI_LVC1_N")
	)
	(segment
		(start 334.95869 -228.07041)
		(end 334.390238 -228.07041)
		(width 0.0889)
		(layer "B.Cu")
		(net "H_CPU0_NMI_LVC1_N")
	)
	(segment
		(start 343.805764 -227.960682)
		(end 343.791032 -227.969318)
		(width 0.0889)
		(layer "B.Cu")
		(net "H_CPU0_NMI_LVC1_N")
	)
	(segment
		(start 342.865964 -227.960682)
		(end 342.851232 -227.969318)
		(width 0.0889)
		(layer "B.Cu")
		(net "H_CPU0_NMI_LVC1_N")
	)
	(segment
		(start 319.073022 -188.251084)
		(end 319.073022 -186.36996)
		(width 0.12954)
		(layer "B.Cu")
		(net "H_CPU0_NMI_LVC1_N")
	)
	(segment
		(start 347.560392 -227.963222)
		(end 347.549978 -227.969318)
		(width 0.0889)
		(layer "B.Cu")
		(net "H_CPU0_NMI_LVC1_N")
	)
	(segment
		(start 335.898236 -227.969318)
		(end 335.887822 -227.963222)
		(width 0.0889)
		(layer "B.Cu")
		(net "H_CPU0_NMI_LVC1_N")
	)
	(segment
		(start 330.172314 -226.68103)
		(end 327.72731 -226.68103)
		(width 0.12954)
		(layer "B.Cu")
		(net "H_CPU0_NMI_LVC1_N")
	)
	(segment
		(start 338.166964 -227.960682)
		(end 338.152232 -227.969318)
		(width 0.0889)
		(layer "B.Cu")
		(net "H_CPU0_NMI_LVC1_N")
	)
	(segment
		(start 320.448178 -219.401898)
		(end 320.448178 -216.84361)
		(width 0.12954)
		(layer "B.Cu")
		(net "H_CPU0_NMI_LVC1_N")
	)
	(segment
		(start 334.390238 -228.07041)
		(end 331.561694 -228.07041)
		(width 0.12954)
		(layer "B.Cu")
		(net "H_CPU0_NMI_LVC1_N")
	)
	(segment
		(start 349.444564 -227.960682)
		(end 349.429832 -227.969318)
		(width 0.0889)
		(layer "B.Cu")
		(net "H_CPU0_NMI_LVC1_N")
	)
	(segment
		(start 331.561694 -228.07041)
		(end 330.172314 -226.68103)
		(width 0.12954)
		(layer "B.Cu")
		(net "H_CPU0_NMI_LVC1_N")
	)
	(segment
		(start 336.287364 -227.960682)
		(end 336.272632 -227.969318)
		(width 0.0889)
		(layer "B.Cu")
		(net "H_CPU0_NMI_LVC1_N")
	)
	(arc
		(start 345.296236 -227.969318)
		(mid 345.022007 -227.893393)
		(end 344.745564 -227.960682)
		(width 0.0889)
		(layer "B.Cu")
		(net "H_CPU0_NMI_LVC1_N")
	)
	(arc
		(start 339.092032 -227.969318)
		(mid 338.904834 -228.019461)
		(end 338.717636 -227.969318)
		(width 0.0889)
		(layer "B.Cu")
		(net "H_CPU0_NMI_LVC1_N")
	)
	(arc
		(start 344.730832 -227.969318)
		(mid 344.543634 -228.019461)
		(end 344.356436 -227.969318)
		(width 0.0889)
		(layer "B.Cu")
		(net "H_CPU0_NMI_LVC1_N")
	)
	(arc
		(start 343.791032 -227.969318)
		(mid 343.603834 -228.019461)
		(end 343.416636 -227.969318)
		(width 0.0889)
		(layer "B.Cu")
		(net "H_CPU0_NMI_LVC1_N")
	)
	(arc
		(start 338.717636 -227.969318)
		(mid 338.443407 -227.893393)
		(end 338.166964 -227.960682)
		(width 0.0889)
		(layer "B.Cu")
		(net "H_CPU0_NMI_LVC1_N")
	)
	(arc
		(start 348.490032 -227.969318)
		(mid 348.302834 -228.019461)
		(end 348.115636 -227.969318)
		(width 0.0889)
		(layer "B.Cu")
		(net "H_CPU0_NMI_LVC1_N")
	)
	(arc
		(start 342.851232 -227.969318)
		(mid 342.664034 -228.019461)
		(end 342.476836 -227.969318)
		(width 0.0889)
		(layer "B.Cu")
		(net "H_CPU0_NMI_LVC1_N")
	)
	(arc
		(start 342.476836 -227.969318)
		(mid 342.202607 -227.893393)
		(end 341.926164 -227.960682)
		(width 0.0889)
		(layer "B.Cu")
		(net "H_CPU0_NMI_LVC1_N")
	)
	(arc
		(start 338.152232 -227.969318)
		(mid 337.965034 -228.019461)
		(end 337.777836 -227.969318)
		(width 0.0889)
		(layer "B.Cu")
		(net "H_CPU0_NMI_LVC1_N")
	)
	(arc
		(start 336.838036 -227.969318)
		(mid 336.563807 -227.893393)
		(end 336.287364 -227.960682)
		(width 0.0889)
		(layer "B.Cu")
		(net "H_CPU0_NMI_LVC1_N")
	)
	(arc
		(start 337.212432 -227.969318)
		(mid 337.025234 -228.019461)
		(end 336.838036 -227.969318)
		(width 0.0889)
		(layer "B.Cu")
		(net "H_CPU0_NMI_LVC1_N")
	)
	(arc
		(start 346.610432 -227.969318)
		(mid 346.423234 -228.019461)
		(end 346.236036 -227.969318)
		(width 0.0889)
		(layer "B.Cu")
		(net "H_CPU0_NMI_LVC1_N")
	)
	(arc
		(start 336.272632 -227.969318)
		(mid 336.085434 -228.019461)
		(end 335.898236 -227.969318)
		(width 0.0889)
		(layer "B.Cu")
		(net "H_CPU0_NMI_LVC1_N")
	)
	(arc
		(start 345.670632 -227.969318)
		(mid 345.483434 -228.019461)
		(end 345.296236 -227.969318)
		(width 0.0889)
		(layer "B.Cu")
		(net "H_CPU0_NMI_LVC1_N")
	)
	(arc
		(start 337.777836 -227.969318)
		(mid 337.503607 -227.893393)
		(end 337.227164 -227.960682)
		(width 0.0889)
		(layer "B.Cu")
		(net "H_CPU0_NMI_LVC1_N")
	)
	(arc
		(start 349.936816 -227.939854)
		(mid 349.688311 -227.893888)
		(end 349.444564 -227.960682)
		(width 0.0889)
		(layer "B.Cu")
		(net "H_CPU0_NMI_LVC1_N")
	)
	(arc
		(start 340.597236 -227.969318)
		(mid 340.320423 -227.893482)
		(end 340.041992 -227.963222)
		(width 0.0889)
		(layer "B.Cu")
		(net "H_CPU0_NMI_LVC1_N")
	)
	(arc
		(start 335.332578 -227.969318)
		(mid 335.152343 -228.044668)
		(end 334.95869 -228.07041)
		(width 0.0889)
		(layer "B.Cu")
		(net "H_CPU0_NMI_LVC1_N")
	)
	(arc
		(start 341.537036 -227.969318)
		(mid 341.262807 -227.893393)
		(end 340.986364 -227.960682)
		(width 0.0889)
		(layer "B.Cu")
		(net "H_CPU0_NMI_LVC1_N")
	)
	(arc
		(start 349.055436 -227.969318)
		(mid 348.781207 -227.893393)
		(end 348.504764 -227.960682)
		(width 0.0889)
		(layer "B.Cu")
		(net "H_CPU0_NMI_LVC1_N")
	)
	(arc
		(start 344.356436 -227.969318)
		(mid 344.082207 -227.893393)
		(end 343.805764 -227.960682)
		(width 0.0889)
		(layer "B.Cu")
		(net "H_CPU0_NMI_LVC1_N")
	)
	(arc
		(start 349.429832 -227.969318)
		(mid 349.242634 -228.019461)
		(end 349.055436 -227.969318)
		(width 0.0889)
		(layer "B.Cu")
		(net "H_CPU0_NMI_LVC1_N")
	)
	(arc
		(start 339.646768 -227.963222)
		(mid 339.36859 -227.89353)
		(end 339.092032 -227.969318)
		(width 0.0889)
		(layer "B.Cu")
		(net "H_CPU0_NMI_LVC1_N")
	)
	(arc
		(start 340.971632 -227.969318)
		(mid 340.784434 -228.019461)
		(end 340.597236 -227.969318)
		(width 0.0889)
		(layer "B.Cu")
		(net "H_CPU0_NMI_LVC1_N")
	)
	(arc
		(start 347.175582 -227.969318)
		(mid 346.899023 -227.893609)
		(end 346.620846 -227.963222)
		(width 0.0889)
		(layer "B.Cu")
		(net "H_CPU0_NMI_LVC1_N")
	)
	(arc
		(start 340.031578 -227.969318)
		(mid 339.84438 -228.019461)
		(end 339.657182 -227.969318)
		(width 0.0889)
		(layer "B.Cu")
		(net "H_CPU0_NMI_LVC1_N")
	)
	(arc
		(start 346.236036 -227.969318)
		(mid 345.953334 -227.893576)
		(end 345.670632 -227.969318)
		(width 0.0889)
		(layer "B.Cu")
		(net "H_CPU0_NMI_LVC1_N")
	)
	(arc
		(start 347.549978 -227.969318)
		(mid 347.36278 -228.019461)
		(end 347.175582 -227.969318)
		(width 0.0889)
		(layer "B.Cu")
		(net "H_CPU0_NMI_LVC1_N")
	)
	(arc
		(start 341.911432 -227.969318)
		(mid 341.724234 -228.019461)
		(end 341.537036 -227.969318)
		(width 0.0889)
		(layer "B.Cu")
		(net "H_CPU0_NMI_LVC1_N")
	)
	(arc
		(start 343.416636 -227.969318)
		(mid 343.142407 -227.893393)
		(end 342.865964 -227.960682)
		(width 0.0889)
		(layer "B.Cu")
		(net "H_CPU0_NMI_LVC1_N")
	)
	(arc
		(start 335.887822 -227.963222)
		(mid 335.60939 -227.893408)
		(end 335.332578 -227.969318)
		(width 0.0889)
		(layer "B.Cu")
		(net "H_CPU0_NMI_LVC1_N")
	)
	(arc
		(start 348.115636 -227.969318)
		(mid 347.838823 -227.893482)
		(end 347.560392 -227.963222)
		(width 0.0889)
		(layer "B.Cu")
		(net "H_CPU0_NMI_LVC1_N")
	)
	(segment
		(start 129.46888 -99.767898)
		(end 129.46888 -99.151948)
		(width 0.12954)
		(layer "F.Cu")
		(net "H_CPU0_MEMTRIP_LVC1_R_N")
	)
	(segment
		(start 350.18218 -232.528618)
		(end 350.182434 -232.528364)
		(width 0.12954)
		(layer "F.Cu")
		(net "H_CPU0_MEMTRIP_LVC1_R_N")
	)
	(segment
		(start 350.18218 -233.064304)
		(end 350.18218 -232.528618)
		(width 0.12954)
		(layer "F.Cu")
		(net "H_CPU0_MEMTRIP_LVC1_R_N")
	)
	(segment
		(start 128.45288 -99.767898)
		(end 129.46888 -99.767898)
		(width 0.12954)
		(layer "F.Cu")
		(net "H_CPU0_MEMTRIP_LVC1_R_N")
	)
	(via
		(at 256.17424 -149.779228)
		(size 0.508)
		(drill 0.254)
		(layers "F.Cu" "B.Cu")
		(net "H_CPU0_MEMTRIP_LVC1_R_N")
	)
	(via
		(at 319.048638 -232.40873)
		(size 0.6604)
		(drill 0.3302)
		(layers "F.Cu" "B.Cu")
		(net "H_CPU0_MEMTRIP_LVC1_R_N")
	)
	(via
		(at 134.239 -143.947388)
		(size 0.508)
		(drill 0.254)
		(layers "F.Cu" "B.Cu")
		(net "H_CPU0_MEMTRIP_LVC1_R_N")
	)
	(via
		(at 350.182434 -232.528364)
		(size 0.4572)
		(drill 0.2032)
		(layers "F.Cu" "B.Cu")
		(net "H_CPU0_MEMTRIP_LVC1_R_N")
	)
	(via
		(at 129.46888 -99.151948)
		(size 0.508)
		(drill 0.254)
		(layers "F.Cu" "B.Cu")
		(net "H_CPU0_MEMTRIP_LVC1_R_N")
	)
	(segment
		(start 350.182434 -232.528364)
		(end 349.28556 -232.160318)
		(width 0.0889)
		(layer "B.Cu")
		(net "H_CPU0_MEMTRIP_LVC1_R_N")
	)
	(segment
		(start 342.865964 -232.212642)
		(end 342.851232 -232.204006)
		(width 0.0889)
		(layer "B.Cu")
		(net "H_CPU0_MEMTRIP_LVC1_R_N")
	)
	(segment
		(start 346.620592 -232.210102)
		(end 346.610178 -232.204006)
		(width 0.0889)
		(layer "B.Cu")
		(net "H_CPU0_MEMTRIP_LVC1_R_N")
	)
	(segment
		(start 333.049118 -232.153968)
		(end 333.04861 -232.15346)
		(width 0.0889)
		(layer "B.Cu")
		(net "H_CPU0_MEMTRIP_LVC1_R_N")
	)
	(segment
		(start 256.17424 -159.082994)
		(end 256.17424 -149.779228)
		(width 0.12954)
		(layer "B.Cu")
		(net "H_CPU0_MEMTRIP_LVC1_R_N")
	)
	(segment
		(start 322.642738 -232.40873)
		(end 319.048638 -232.40873)
		(width 0.12954)
		(layer "B.Cu")
		(net "H_CPU0_MEMTRIP_LVC1_R_N")
	)
	(segment
		(start 301.899574 -177.736246)
		(end 274.827492 -177.736246)
		(width 0.12954)
		(layer "B.Cu")
		(net "H_CPU0_MEMTRIP_LVC1_R_N")
	)
	(segment
		(start 338.166964 -232.212642)
		(end 338.152232 -232.204006)
		(width 0.0889)
		(layer "B.Cu")
		(net "H_CPU0_MEMTRIP_LVC1_R_N")
	)
	(segment
		(start 348.498414 -232.208832)
		(end 348.490032 -232.204006)
		(width 0.0889)
		(layer "B.Cu")
		(net "H_CPU0_MEMTRIP_LVC1_R_N")
	)
	(segment
		(start 349.064072 -232.208832)
		(end 349.064072 -232.209086)
		(width 0.0889)
		(layer "B.Cu")
		(net "H_CPU0_MEMTRIP_LVC1_R_N")
	)
	(segment
		(start 344.745564 -232.212642)
		(end 344.730832 -232.204006)
		(width 0.0889)
		(layer "B.Cu")
		(net "H_CPU0_MEMTRIP_LVC1_R_N")
	)
	(segment
		(start 332.826614 -232.654856)
		(end 332.572614 -232.908856)
		(width 0.0889)
		(layer "B.Cu")
		(net "H_CPU0_MEMTRIP_LVC1_R_N")
	)
	(segment
		(start 314.659772 -232.870756)
		(end 314.070238 -232.870756)
		(width 0.12954)
		(layer "B.Cu")
		(net "H_CPU0_MEMTRIP_LVC1_R_N")
	)
	(segment
		(start 333.04861 -232.15346)
		(end 332.826614 -232.375456)
		(width 0.0889)
		(layer "B.Cu")
		(net "H_CPU0_MEMTRIP_LVC1_R_N")
	)
	(segment
		(start 336.287364 -232.212642)
		(end 336.272632 -232.204006)
		(width 0.0889)
		(layer "B.Cu")
		(net "H_CPU0_MEMTRIP_LVC1_R_N")
	)
	(segment
		(start 323.142864 -232.908856)
		(end 322.642738 -232.40873)
		(width 0.12954)
		(layer "B.Cu")
		(net "H_CPU0_MEMTRIP_LVC1_R_N")
	)
	(segment
		(start 347.564964 -232.212642)
		(end 347.550232 -232.204006)
		(width 0.0889)
		(layer "B.Cu")
		(net "H_CPU0_MEMTRIP_LVC1_R_N")
	)
	(segment
		(start 311.313576 -193.438526)
		(end 311.313576 -191.177672)
		(width 0.12954)
		(layer "B.Cu")
		(net "H_CPU0_MEMTRIP_LVC1_R_N")
	)
	(segment
		(start 311.220612 -193.53149)
		(end 311.313576 -193.438526)
		(width 0.12954)
		(layer "B.Cu")
		(net "H_CPU0_MEMTRIP_LVC1_R_N")
	)
	(segment
		(start 311.906158 -231.58323)
		(end 311.220612 -230.897684)
		(width 0.12954)
		(layer "B.Cu")
		(net "H_CPU0_MEMTRIP_LVC1_R_N")
	)
	(segment
		(start 319.048638 -232.40873)
		(end 315.121798 -232.40873)
		(width 0.12954)
		(layer "B.Cu")
		(net "H_CPU0_MEMTRIP_LVC1_R_N")
	)
	(segment
		(start 312.782712 -231.58323)
		(end 311.906158 -231.58323)
		(width 0.12954)
		(layer "B.Cu")
		(net "H_CPU0_MEMTRIP_LVC1_R_N")
	)
	(segment
		(start 311.313576 -191.177672)
		(end 312.762138 -189.72911)
		(width 0.12954)
		(layer "B.Cu")
		(net "H_CPU0_MEMTRIP_LVC1_R_N")
	)
	(segment
		(start 337.227164 -232.212642)
		(end 337.212432 -232.204006)
		(width 0.0889)
		(layer "B.Cu")
		(net "H_CPU0_MEMTRIP_LVC1_R_N")
	)
	(segment
		(start 343.805764 -232.212642)
		(end 343.791032 -232.204006)
		(width 0.0889)
		(layer "B.Cu")
		(net "H_CPU0_MEMTRIP_LVC1_R_N")
	)
	(segment
		(start 340.041992 -232.210102)
		(end 340.031578 -232.204006)
		(width 0.0889)
		(layer "B.Cu")
		(net "H_CPU0_MEMTRIP_LVC1_R_N")
	)
	(segment
		(start 332.826614 -232.375456)
		(end 332.826614 -232.654856)
		(width 0.0889)
		(layer "B.Cu")
		(net "H_CPU0_MEMTRIP_LVC1_R_N")
	)
	(segment
		(start 312.762138 -188.59881)
		(end 301.899574 -177.736246)
		(width 0.12954)
		(layer "B.Cu")
		(net "H_CPU0_MEMTRIP_LVC1_R_N")
	)
	(segment
		(start 311.220612 -230.897684)
		(end 311.220612 -193.53149)
		(width 0.12954)
		(layer "B.Cu")
		(net "H_CPU0_MEMTRIP_LVC1_R_N")
	)
	(segment
		(start 274.827492 -177.736246)
		(end 256.17424 -159.082994)
		(width 0.12954)
		(layer "B.Cu")
		(net "H_CPU0_MEMTRIP_LVC1_R_N")
	)
	(segment
		(start 334.205834 -232.153968)
		(end 333.049118 -232.153968)
		(width 0.0889)
		(layer "B.Cu")
		(net "H_CPU0_MEMTRIP_LVC1_R_N")
	)
	(segment
		(start 331.314552 -232.908856)
		(end 323.142864 -232.908856)
		(width 0.12954)
		(layer "B.Cu")
		(net "H_CPU0_MEMTRIP_LVC1_R_N")
	)
	(segment
		(start 345.681046 -232.210102)
		(end 345.670632 -232.204006)
		(width 0.0889)
		(layer "B.Cu")
		(net "H_CPU0_MEMTRIP_LVC1_R_N")
	)
	(segment
		(start 340.986364 -232.212642)
		(end 340.971632 -232.204006)
		(width 0.0889)
		(layer "B.Cu")
		(net "H_CPU0_MEMTRIP_LVC1_R_N")
	)
	(segment
		(start 332.572614 -232.908856)
		(end 331.314552 -232.908856)
		(width 0.0889)
		(layer "B.Cu")
		(net "H_CPU0_MEMTRIP_LVC1_R_N")
	)
	(segment
		(start 339.102446 -232.210102)
		(end 339.092032 -232.204006)
		(width 0.0889)
		(layer "B.Cu")
		(net "H_CPU0_MEMTRIP_LVC1_R_N")
	)
	(segment
		(start 314.070238 -232.870756)
		(end 312.782712 -231.58323)
		(width 0.12954)
		(layer "B.Cu")
		(net "H_CPU0_MEMTRIP_LVC1_R_N")
	)
	(segment
		(start 312.762138 -189.72911)
		(end 312.762138 -188.59881)
		(width 0.12954)
		(layer "B.Cu")
		(net "H_CPU0_MEMTRIP_LVC1_R_N")
	)
	(segment
		(start 315.121798 -232.40873)
		(end 314.659772 -232.870756)
		(width 0.12954)
		(layer "B.Cu")
		(net "H_CPU0_MEMTRIP_LVC1_R_N")
	)
	(arc
		(start 340.971632 -232.204006)
		(mid 340.784434 -232.153863)
		(end 340.597236 -232.204006)
		(width 0.0889)
		(layer "B.Cu")
		(net "H_CPU0_MEMTRIP_LVC1_R_N")
	)
	(arc
		(start 349.064072 -232.209086)
		(mid 348.781196 -232.284828)
		(end 348.498414 -232.208832)
		(width 0.0889)
		(layer "B.Cu")
		(net "H_CPU0_MEMTRIP_LVC1_R_N")
	)
	(arc
		(start 340.597236 -232.204006)
		(mid 340.320423 -232.279876)
		(end 340.041992 -232.210102)
		(width 0.0889)
		(layer "B.Cu")
		(net "H_CPU0_MEMTRIP_LVC1_R_N")
	)
	(arc
		(start 345.296236 -232.204006)
		(mid 345.022037 -232.279841)
		(end 344.745564 -232.212642)
		(width 0.0889)
		(layer "B.Cu")
		(net "H_CPU0_MEMTRIP_LVC1_R_N")
	)
	(arc
		(start 347.550232 -232.204006)
		(mid 347.363034 -232.153863)
		(end 347.175836 -232.204006)
		(width 0.0889)
		(layer "B.Cu")
		(net "H_CPU0_MEMTRIP_LVC1_R_N")
	)
	(arc
		(start 336.838036 -232.204006)
		(mid 336.563837 -232.279841)
		(end 336.287364 -232.212642)
		(width 0.0889)
		(layer "B.Cu")
		(net "H_CPU0_MEMTRIP_LVC1_R_N")
	)
	(arc
		(start 349.28556 -232.160318)
		(mid 349.171042 -232.167366)
		(end 349.064072 -232.208832)
		(width 0.0889)
		(layer "B.Cu")
		(net "H_CPU0_MEMTRIP_LVC1_R_N")
	)
	(arc
		(start 334.958436 -232.204006)
		(mid 334.675734 -232.279782)
		(end 334.393032 -232.204006)
		(width 0.0889)
		(layer "B.Cu")
		(net "H_CPU0_MEMTRIP_LVC1_R_N")
	)
	(arc
		(start 343.416636 -232.204006)
		(mid 343.142437 -232.279841)
		(end 342.865964 -232.212642)
		(width 0.0889)
		(layer "B.Cu")
		(net "H_CPU0_MEMTRIP_LVC1_R_N")
	)
	(arc
		(start 346.235782 -232.204006)
		(mid 345.959223 -232.279749)
		(end 345.681046 -232.210102)
		(width 0.0889)
		(layer "B.Cu")
		(net "H_CPU0_MEMTRIP_LVC1_R_N")
	)
	(arc
		(start 346.610178 -232.204006)
		(mid 346.42298 -232.153863)
		(end 346.235782 -232.204006)
		(width 0.0889)
		(layer "B.Cu")
		(net "H_CPU0_MEMTRIP_LVC1_R_N")
	)
	(arc
		(start 341.537036 -232.204006)
		(mid 341.262837 -232.279841)
		(end 340.986364 -232.212642)
		(width 0.0889)
		(layer "B.Cu")
		(net "H_CPU0_MEMTRIP_LVC1_R_N")
	)
	(arc
		(start 338.152232 -232.204006)
		(mid 337.965034 -232.153863)
		(end 337.777836 -232.204006)
		(width 0.0889)
		(layer "B.Cu")
		(net "H_CPU0_MEMTRIP_LVC1_R_N")
	)
	(arc
		(start 339.657182 -232.204006)
		(mid 339.380623 -232.279749)
		(end 339.102446 -232.210102)
		(width 0.0889)
		(layer "B.Cu")
		(net "H_CPU0_MEMTRIP_LVC1_R_N")
	)
	(arc
		(start 340.031578 -232.204006)
		(mid 339.84438 -232.153863)
		(end 339.657182 -232.204006)
		(width 0.0889)
		(layer "B.Cu")
		(net "H_CPU0_MEMTRIP_LVC1_R_N")
	)
	(arc
		(start 337.777836 -232.204006)
		(mid 337.503637 -232.279841)
		(end 337.227164 -232.212642)
		(width 0.0889)
		(layer "B.Cu")
		(net "H_CPU0_MEMTRIP_LVC1_R_N")
	)
	(arc
		(start 337.212432 -232.204006)
		(mid 337.025234 -232.153863)
		(end 336.838036 -232.204006)
		(width 0.0889)
		(layer "B.Cu")
		(net "H_CPU0_MEMTRIP_LVC1_R_N")
	)
	(arc
		(start 341.911432 -232.204006)
		(mid 341.724234 -232.153863)
		(end 341.537036 -232.204006)
		(width 0.0889)
		(layer "B.Cu")
		(net "H_CPU0_MEMTRIP_LVC1_R_N")
	)
	(arc
		(start 348.115636 -232.204006)
		(mid 347.841437 -232.279841)
		(end 347.564964 -232.212642)
		(width 0.0889)
		(layer "B.Cu")
		(net "H_CPU0_MEMTRIP_LVC1_R_N")
	)
	(arc
		(start 343.791032 -232.204006)
		(mid 343.603834 -232.153863)
		(end 343.416636 -232.204006)
		(width 0.0889)
		(layer "B.Cu")
		(net "H_CPU0_MEMTRIP_LVC1_R_N")
	)
	(arc
		(start 342.851232 -232.204006)
		(mid 342.664034 -232.153863)
		(end 342.476836 -232.204006)
		(width 0.0889)
		(layer "B.Cu")
		(net "H_CPU0_MEMTRIP_LVC1_R_N")
	)
	(arc
		(start 345.670632 -232.204006)
		(mid 345.483434 -232.153863)
		(end 345.296236 -232.204006)
		(width 0.0889)
		(layer "B.Cu")
		(net "H_CPU0_MEMTRIP_LVC1_R_N")
	)
	(arc
		(start 336.272632 -232.204006)
		(mid 336.085434 -232.153863)
		(end 335.898236 -232.204006)
		(width 0.0889)
		(layer "B.Cu")
		(net "H_CPU0_MEMTRIP_LVC1_R_N")
	)
	(arc
		(start 339.092032 -232.204006)
		(mid 338.904834 -232.153863)
		(end 338.717636 -232.204006)
		(width 0.0889)
		(layer "B.Cu")
		(net "H_CPU0_MEMTRIP_LVC1_R_N")
	)
	(arc
		(start 335.898236 -232.204006)
		(mid 335.615534 -232.279782)
		(end 335.332832 -232.204006)
		(width 0.0889)
		(layer "B.Cu")
		(net "H_CPU0_MEMTRIP_LVC1_R_N")
	)
	(arc
		(start 344.356436 -232.204006)
		(mid 344.082237 -232.279841)
		(end 343.805764 -232.212642)
		(width 0.0889)
		(layer "B.Cu")
		(net "H_CPU0_MEMTRIP_LVC1_R_N")
	)
	(arc
		(start 338.717636 -232.204006)
		(mid 338.443437 -232.279841)
		(end 338.166964 -232.212642)
		(width 0.0889)
		(layer "B.Cu")
		(net "H_CPU0_MEMTRIP_LVC1_R_N")
	)
	(arc
		(start 334.393032 -232.204006)
		(mid 334.302725 -232.166677)
		(end 334.205834 -232.153968)
		(width 0.0889)
		(layer "B.Cu")
		(net "H_CPU0_MEMTRIP_LVC1_R_N")
	)
	(arc
		(start 347.175836 -232.204006)
		(mid 346.899023 -232.279876)
		(end 346.620592 -232.210102)
		(width 0.0889)
		(layer "B.Cu")
		(net "H_CPU0_MEMTRIP_LVC1_R_N")
	)
	(arc
		(start 348.490032 -232.204006)
		(mid 348.302834 -232.153863)
		(end 348.115636 -232.204006)
		(width 0.0889)
		(layer "B.Cu")
		(net "H_CPU0_MEMTRIP_LVC1_R_N")
	)
	(arc
		(start 342.476836 -232.204006)
		(mid 342.194134 -232.279782)
		(end 341.911432 -232.204006)
		(width 0.0889)
		(layer "B.Cu")
		(net "H_CPU0_MEMTRIP_LVC1_R_N")
	)
	(arc
		(start 344.730832 -232.204006)
		(mid 344.543634 -232.153863)
		(end 344.356436 -232.204006)
		(width 0.0889)
		(layer "B.Cu")
		(net "H_CPU0_MEMTRIP_LVC1_R_N")
	)
	(arc
		(start 335.332832 -232.204006)
		(mid 335.145634 -232.153863)
		(end 334.958436 -232.204006)
		(width 0.0889)
		(layer "B.Cu")
		(net "H_CPU0_MEMTRIP_LVC1_R_N")
	)
	(segment
		(start 134.447788 -115.090956)
		(end 133.2992 -113.942368)
		(width 0.127)
		(layer "In2.Cu")
		(net "H_CPU0_MEMTRIP_LVC1_R_N")
	)
	(segment
		(start 133.2992 -113.942368)
		(end 133.2992 -102.982268)
		(width 0.127)
		(layer "In2.Cu")
		(net "H_CPU0_MEMTRIP_LVC1_R_N")
	)
	(segment
		(start 134.239 -143.947388)
		(end 134.447788 -143.7386)
		(width 0.127)
		(layer "In2.Cu")
		(net "H_CPU0_MEMTRIP_LVC1_R_N")
	)
	(segment
		(start 134.447788 -143.7386)
		(end 134.447788 -115.090956)
		(width 0.127)
		(layer "In2.Cu")
		(net "H_CPU0_MEMTRIP_LVC1_R_N")
	)
	(segment
		(start 133.2992 -102.982268)
		(end 129.46888 -99.151948)
		(width 0.127)
		(layer "In2.Cu")
		(net "H_CPU0_MEMTRIP_LVC1_R_N")
	)
	(segment
		(start 256.17424 -149.779228)
		(end 254.30988 -149.779228)
		(width 0.127)
		(layer "In13.Cu")
		(net "H_CPU0_MEMTRIP_LVC1_R_N")
	)
	(segment
		(start 153.338022 -146.294348)
		(end 149.108922 -142.065248)
		(width 0.127)
		(layer "In13.Cu")
		(net "H_CPU0_MEMTRIP_LVC1_R_N")
	)
	(segment
		(start 213.32444 -152.872948)
		(end 203.84008 -152.872948)
		(width 0.127)
		(layer "In13.Cu")
		(net "H_CPU0_MEMTRIP_LVC1_R_N")
	)
	(segment
		(start 188.95568 -160.010348)
		(end 180.43144 -151.486108)
		(width 0.127)
		(layer "In13.Cu")
		(net "H_CPU0_MEMTRIP_LVC1_R_N")
	)
	(segment
		(start 149.108922 -142.065248)
		(end 136.12114 -142.065248)
		(width 0.127)
		(layer "In13.Cu")
		(net "H_CPU0_MEMTRIP_LVC1_R_N")
	)
	(segment
		(start 180.43144 -151.0411)
		(end 179.128674 -149.738334)
		(width 0.127)
		(layer "In13.Cu")
		(net "H_CPU0_MEMTRIP_LVC1_R_N")
	)
	(segment
		(start 254.30988 -149.779228)
		(end 253.82982 -150.259288)
		(width 0.127)
		(layer "In13.Cu")
		(net "H_CPU0_MEMTRIP_LVC1_R_N")
	)
	(segment
		(start 175.390048 -146.294348)
		(end 153.338022 -146.294348)
		(width 0.127)
		(layer "In13.Cu")
		(net "H_CPU0_MEMTRIP_LVC1_R_N")
	)
	(segment
		(start 196.70268 -160.010348)
		(end 188.95568 -160.010348)
		(width 0.127)
		(layer "In13.Cu")
		(net "H_CPU0_MEMTRIP_LVC1_R_N")
	)
	(segment
		(start 136.12114 -142.065248)
		(end 134.239 -143.947388)
		(width 0.127)
		(layer "In13.Cu")
		(net "H_CPU0_MEMTRIP_LVC1_R_N")
	)
	(segment
		(start 179.128674 -149.738334)
		(end 178.834034 -149.738334)
		(width 0.127)
		(layer "In13.Cu")
		(net "H_CPU0_MEMTRIP_LVC1_R_N")
	)
	(segment
		(start 203.84008 -152.872948)
		(end 196.70268 -160.010348)
		(width 0.127)
		(layer "In13.Cu")
		(net "H_CPU0_MEMTRIP_LVC1_R_N")
	)
	(segment
		(start 180.43144 -151.486108)
		(end 180.43144 -151.0411)
		(width 0.127)
		(layer "In13.Cu")
		(net "H_CPU0_MEMTRIP_LVC1_R_N")
	)
	(segment
		(start 215.9381 -150.259288)
		(end 213.32444 -152.872948)
		(width 0.127)
		(layer "In13.Cu")
		(net "H_CPU0_MEMTRIP_LVC1_R_N")
	)
	(segment
		(start 253.82982 -150.259288)
		(end 215.9381 -150.259288)
		(width 0.127)
		(layer "In13.Cu")
		(net "H_CPU0_MEMTRIP_LVC1_R_N")
	)
	(segment
		(start 178.834034 -149.738334)
		(end 175.390048 -146.294348)
		(width 0.127)
		(layer "In13.Cu")
		(net "H_CPU0_MEMTRIP_LVC1_R_N")
	)
	(segment
		(start 132.28828 -88.966548)
		(end 132.28828 -94.765368)
		(width 0.12954)
		(layer "F.Cu")
		(net "H_CPU0_MEMTRIP_LVC1_N")
	)
	(segment
		(start 181.355746 -108.975398)
		(end 181.755796 -108.575348)
		(width 0.12954)
		(layer "F.Cu")
		(net "H_CPU0_MEMTRIP_LVC1_N")
	)
	(segment
		(start 132.54228 -88.712548)
		(end 132.28828 -88.966548)
		(width 0.12954)
		(layer "F.Cu")
		(net "H_CPU0_MEMTRIP_LVC1_N")
	)
	(segment
		(start 131.50088 -95.552768)
		(end 131.50088 -99.767898)
		(width 0.12954)
		(layer "F.Cu")
		(net "H_CPU0_MEMTRIP_LVC1_N")
	)
	(segment
		(start 132.54228 -85.537548)
		(end 132.54228 -88.712548)
		(width 0.12954)
		(layer "F.Cu")
		(net "H_CPU0_MEMTRIP_LVC1_N")
	)
	(segment
		(start 132.28828 -94.765368)
		(end 131.50088 -95.552768)
		(width 0.12954)
		(layer "F.Cu")
		(net "H_CPU0_MEMTRIP_LVC1_N")
	)
	(via
		(at 132.54228 -85.537548)
		(size 0.508)
		(drill 0.254)
		(layers "F.Cu" "B.Cu")
		(net "H_CPU0_MEMTRIP_LVC1_N")
	)
	(via
		(at 181.755796 -108.575348)
		(size 0.4572)
		(drill 0.254)
		(layers "F.Cu" "B.Cu")
		(net "H_CPU0_MEMTRIP_LVC1_N")
	)
	(segment
		(start 169.13606 -98.555048)
		(end 170.53052 -99.949508)
		(width 0.127)
		(layer "In15.Cu")
		(net "H_CPU0_MEMTRIP_LVC1_N")
	)
	(segment
		(start 178.33594 -101.884988)
		(end 178.33594 -104.06634)
		(width 0.127)
		(layer "In15.Cu")
		(net "H_CPU0_MEMTRIP_LVC1_N")
	)
	(segment
		(start 150.573486 -99.177348)
		(end 159.3342 -99.177348)
		(width 0.127)
		(layer "In15.Cu")
		(net "H_CPU0_MEMTRIP_LVC1_N")
	)
	(segment
		(start 179.518564 -105.248964)
		(end 179.518564 -105.782364)
		(width 0.127)
		(layer "In15.Cu")
		(net "H_CPU0_MEMTRIP_LVC1_N")
	)
	(segment
		(start 132.54228 -85.537548)
		(end 132.62356 -85.456268)
		(width 0.127)
		(layer "In15.Cu")
		(net "H_CPU0_MEMTRIP_LVC1_N")
	)
	(segment
		(start 176.01946 -100.409248)
		(end 176.8602 -100.409248)
		(width 0.127)
		(layer "In15.Cu")
		(net "H_CPU0_MEMTRIP_LVC1_N")
	)
	(segment
		(start 170.53052 -99.949508)
		(end 175.55972 -99.949508)
		(width 0.127)
		(layer "In15.Cu")
		(net "H_CPU0_MEMTRIP_LVC1_N")
	)
	(segment
		(start 180.04536 -108.575348)
		(end 181.755796 -108.575348)
		(width 0.127)
		(layer "In15.Cu")
		(net "H_CPU0_MEMTRIP_LVC1_N")
	)
	(segment
		(start 132.62356 -85.456268)
		(end 139.35075 -85.456268)
		(width 0.127)
		(layer "In15.Cu")
		(net "H_CPU0_MEMTRIP_LVC1_N")
	)
	(segment
		(start 140.12672 -88.730582)
		(end 150.573486 -99.177348)
		(width 0.127)
		(layer "In15.Cu")
		(net "H_CPU0_MEMTRIP_LVC1_N")
	)
	(segment
		(start 139.35075 -85.456268)
		(end 140.12672 -86.232238)
		(width 0.127)
		(layer "In15.Cu")
		(net "H_CPU0_MEMTRIP_LVC1_N")
	)
	(segment
		(start 179.518564 -105.782364)
		(end 179.748688 -106.012488)
		(width 0.127)
		(layer "In15.Cu")
		(net "H_CPU0_MEMTRIP_LVC1_N")
	)
	(segment
		(start 178.33594 -104.06634)
		(end 179.518564 -105.248964)
		(width 0.127)
		(layer "In15.Cu")
		(net "H_CPU0_MEMTRIP_LVC1_N")
	)
	(segment
		(start 175.55972 -99.949508)
		(end 176.01946 -100.409248)
		(width 0.127)
		(layer "In15.Cu")
		(net "H_CPU0_MEMTRIP_LVC1_N")
	)
	(segment
		(start 179.748688 -106.012488)
		(end 179.748688 -108.278676)
		(width 0.127)
		(layer "In15.Cu")
		(net "H_CPU0_MEMTRIP_LVC1_N")
	)
	(segment
		(start 179.748688 -108.278676)
		(end 180.04536 -108.575348)
		(width 0.127)
		(layer "In15.Cu")
		(net "H_CPU0_MEMTRIP_LVC1_N")
	)
	(segment
		(start 159.3342 -99.177348)
		(end 159.9565 -98.555048)
		(width 0.127)
		(layer "In15.Cu")
		(net "H_CPU0_MEMTRIP_LVC1_N")
	)
	(segment
		(start 176.8602 -100.409248)
		(end 178.33594 -101.884988)
		(width 0.127)
		(layer "In15.Cu")
		(net "H_CPU0_MEMTRIP_LVC1_N")
	)
	(segment
		(start 140.12672 -86.232238)
		(end 140.12672 -88.730582)
		(width 0.127)
		(layer "In15.Cu")
		(net "H_CPU0_MEMTRIP_LVC1_N")
	)
	(segment
		(start 159.9565 -98.555048)
		(end 169.13606 -98.555048)
		(width 0.127)
		(layer "In15.Cu")
		(net "H_CPU0_MEMTRIP_LVC1_N")
	)
	(segment
		(start 363.339634 -234.691936)
		(end 363.339634 -234.15625)
		(width 0.12954)
		(layer "F.Cu")
		(net "H_CPU0_MEMHOT_OUT_LVC1_R_N")
	)
	(segment
		(start 129.72288 -91.658948)
		(end 129.72288 -92.274898)
		(width 0.12954)
		(layer "F.Cu")
		(net "H_CPU0_MEMHOT_OUT_LVC1_R_N")
	)
	(segment
		(start 363.33938 -234.69219)
		(end 363.339634 -234.691936)
		(width 0.12954)
		(layer "F.Cu")
		(net "H_CPU0_MEMHOT_OUT_LVC1_R_N")
	)
	(segment
		(start 129.72288 -92.274898)
		(end 128.70688 -92.274898)
		(width 0.12954)
		(layer "F.Cu")
		(net "H_CPU0_MEMHOT_OUT_LVC1_R_N")
	)
	(via
		(at 264.34288 -150.332948)
		(size 0.508)
		(drill 0.254)
		(layers "F.Cu" "B.Cu")
		(net "H_CPU0_MEMHOT_OUT_LVC1_R_N")
	)
	(via
		(at 363.339634 -234.15625)
		(size 0.4572)
		(drill 0.2032)
		(layers "F.Cu" "B.Cu")
		(net "H_CPU0_MEMHOT_OUT_LVC1_R_N")
	)
	(via
		(at 129.72288 -91.658948)
		(size 0.508)
		(drill 0.254)
		(layers "F.Cu" "B.Cu")
		(net "H_CPU0_MEMHOT_OUT_LVC1_R_N")
	)
	(via
		(at 131.31038 -150.607268)
		(size 0.508)
		(drill 0.254)
		(layers "F.Cu" "B.Cu")
		(net "H_CPU0_MEMHOT_OUT_LVC1_R_N")
	)
	(segment
		(start 390.47039 -194.211702)
		(end 387.51637 -187.079382)
		(width 0.12954)
		(layer "B.Cu")
		(net "H_CPU0_MEMHOT_OUT_LVC1_R_N")
	)
	(segment
		(start 364.062772 -233.848656)
		(end 364.091982 -233.831638)
		(width 0.0889)
		(layer "B.Cu")
		(net "H_CPU0_MEMHOT_OUT_LVC1_R_N")
	)
	(segment
		(start 384.744214 -234.178856)
		(end 387.754114 -234.178856)
		(width 0.12954)
		(layer "B.Cu")
		(net "H_CPU0_MEMHOT_OUT_LVC1_R_N")
	)
	(segment
		(start 370.105432 -233.831892)
		(end 370.115846 -233.837988)
		(width 0.0889)
		(layer "B.Cu")
		(net "H_CPU0_MEMHOT_OUT_LVC1_R_N")
	)
	(segment
		(start 378.588778 -233.806492)
		(end 378.589032 -233.806492)
		(width 0.0889)
		(layer "B.Cu")
		(net "H_CPU0_MEMHOT_OUT_LVC1_R_N")
	)
	(segment
		(start 379.503432 -233.831892)
		(end 379.518164 -233.840528)
		(width 0.0889)
		(layer "B.Cu")
		(net "H_CPU0_MEMHOT_OUT_LVC1_R_N")
	)
	(segment
		(start 376.185938 -175.74895)
		(end 375.079006 -175.74895)
		(width 0.12954)
		(layer "B.Cu")
		(net "H_CPU0_MEMHOT_OUT_LVC1_R_N")
	)
	(segment
		(start 362.574586 -167.331898)
		(end 348.86773 -161.655252)
		(width 0.12954)
		(layer "B.Cu")
		(net "H_CPU0_MEMHOT_OUT_LVC1_R_N")
	)
	(segment
		(start 387.51637 -187.079382)
		(end 376.185938 -175.74895)
		(width 0.12954)
		(layer "B.Cu")
		(net "H_CPU0_MEMHOT_OUT_LVC1_R_N")
	)
	(segment
		(start 383.828036 -233.831892)
		(end 383.846324 -233.821478)
		(width 0.0889)
		(layer "B.Cu")
		(net "H_CPU0_MEMHOT_OUT_LVC1_R_N")
	)
	(segment
		(start 373.742712 -175.195484)
		(end 371.989858 -173.44263)
		(width 0.12954)
		(layer "B.Cu")
		(net "H_CPU0_MEMHOT_OUT_LVC1_R_N")
	)
	(segment
		(start 376.684032 -233.831892)
		(end 376.694446 -233.837988)
		(width 0.0889)
		(layer "B.Cu")
		(net "H_CPU0_MEMHOT_OUT_LVC1_R_N")
	)
	(segment
		(start 369.163854 -173.921166)
		(end 362.574586 -167.331898)
		(width 0.12954)
		(layer "B.Cu")
		(net "H_CPU0_MEMHOT_OUT_LVC1_R_N")
	)
	(segment
		(start 264.34288 -148.046948)
		(end 264.34288 -150.332948)
		(width 0.12954)
		(layer "B.Cu")
		(net "H_CPU0_MEMHOT_OUT_LVC1_R_N")
	)
	(segment
		(start 378.589032 -233.806492)
		(end 378.68098 -233.84002)
		(width 0.0889)
		(layer "B.Cu")
		(net "H_CPU0_MEMHOT_OUT_LVC1_R_N")
	)
	(segment
		(start 364.466632 -233.831892)
		(end 364.481364 -233.840528)
		(width 0.0889)
		(layer "B.Cu")
		(net "H_CPU0_MEMHOT_OUT_LVC1_R_N")
	)
	(segment
		(start 340.554818 -153.34234)
		(end 321.326256 -145.377408)
		(width 0.12954)
		(layer "B.Cu")
		(net "H_CPU0_MEMHOT_OUT_LVC1_R_N")
	)
	(segment
		(start 389.704072 -233.371136)
		(end 394.73632 -228.338888)
		(width 0.12954)
		(layer "B.Cu")
		(net "H_CPU0_MEMHOT_OUT_LVC1_R_N")
	)
	(segment
		(start 394.73632 -198.477632)
		(end 390.47039 -194.211702)
		(width 0.12954)
		(layer "B.Cu")
		(net "H_CPU0_MEMHOT_OUT_LVC1_R_N")
	)
	(segment
		(start 377.623578 -233.831892)
		(end 377.633992 -233.837988)
		(width 0.0889)
		(layer "B.Cu")
		(net "H_CPU0_MEMHOT_OUT_LVC1_R_N")
	)
	(segment
		(start 369.704112 -173.921166)
		(end 369.163854 -173.921166)
		(width 0.12954)
		(layer "B.Cu")
		(net "H_CPU0_MEMHOT_OUT_LVC1_R_N")
	)
	(segment
		(start 363.339634 -234.15625)
		(end 364.062772 -233.848656)
		(width 0.0889)
		(layer "B.Cu")
		(net "H_CPU0_MEMHOT_OUT_LVC1_R_N")
	)
	(segment
		(start 371.985032 -233.831892)
		(end 371.999764 -233.840528)
		(width 0.0889)
		(layer "B.Cu")
		(net "H_CPU0_MEMHOT_OUT_LVC1_R_N")
	)
	(segment
		(start 371.989858 -173.44263)
		(end 370.859558 -173.44263)
		(width 0.12954)
		(layer "B.Cu")
		(net "H_CPU0_MEMHOT_OUT_LVC1_R_N")
	)
	(segment
		(start 372.924832 -233.831892)
		(end 372.939564 -233.840528)
		(width 0.0889)
		(layer "B.Cu")
		(net "H_CPU0_MEMHOT_OUT_LVC1_R_N")
	)
	(segment
		(start 267.01242 -145.377408)
		(end 264.34288 -148.046948)
		(width 0.12954)
		(layer "B.Cu")
		(net "H_CPU0_MEMHOT_OUT_LVC1_R_N")
	)
	(segment
		(start 365.406432 -233.831892)
		(end 365.421164 -233.840528)
		(width 0.0889)
		(layer "B.Cu")
		(net "H_CPU0_MEMHOT_OUT_LVC1_R_N")
	)
	(segment
		(start 368.225832 -233.831892)
		(end 368.236246 -233.837988)
		(width 0.0889)
		(layer "B.Cu")
		(net "H_CPU0_MEMHOT_OUT_LVC1_R_N")
	)
	(segment
		(start 366.346232 -233.831892)
		(end 366.360964 -233.840528)
		(width 0.0889)
		(layer "B.Cu")
		(net "H_CPU0_MEMHOT_OUT_LVC1_R_N")
	)
	(segment
		(start 321.326256 -145.377408)
		(end 267.01242 -145.377408)
		(width 0.12954)
		(layer "B.Cu")
		(net "H_CPU0_MEMHOT_OUT_LVC1_R_N")
	)
	(segment
		(start 394.73632 -228.338888)
		(end 394.73632 -198.477632)
		(width 0.12954)
		(layer "B.Cu")
		(net "H_CPU0_MEMHOT_OUT_LVC1_R_N")
	)
	(segment
		(start 370.859558 -173.44263)
		(end 369.704112 -173.921166)
		(width 0.12954)
		(layer "B.Cu")
		(net "H_CPU0_MEMHOT_OUT_LVC1_R_N")
	)
	(segment
		(start 387.754114 -234.178856)
		(end 389.704072 -233.371136)
		(width 0.12954)
		(layer "B.Cu")
		(net "H_CPU0_MEMHOT_OUT_LVC1_R_N")
	)
	(segment
		(start 369.720622 -233.837988)
		(end 369.731036 -233.831892)
		(width 0.0889)
		(layer "B.Cu")
		(net "H_CPU0_MEMHOT_OUT_LVC1_R_N")
	)
	(segment
		(start 374.804432 -233.831892)
		(end 374.819164 -233.840528)
		(width 0.0889)
		(layer "B.Cu")
		(net "H_CPU0_MEMHOT_OUT_LVC1_R_N")
	)
	(segment
		(start 375.079006 -175.74895)
		(end 373.742712 -175.195484)
		(width 0.12954)
		(layer "B.Cu")
		(net "H_CPU0_MEMHOT_OUT_LVC1_R_N")
	)
	(segment
		(start 367.285778 -233.831892)
		(end 367.286032 -233.831892)
		(width 0.0889)
		(layer "B.Cu")
		(net "H_CPU0_MEMHOT_OUT_LVC1_R_N")
	)
	(segment
		(start 348.86773 -161.655252)
		(end 340.554818 -153.34234)
		(width 0.12954)
		(layer "B.Cu")
		(net "H_CPU0_MEMHOT_OUT_LVC1_R_N")
	)
	(segment
		(start 384.203194 -233.831638)
		(end 384.744214 -234.178856)
		(width 0.0889)
		(layer "B.Cu")
		(net "H_CPU0_MEMHOT_OUT_LVC1_R_N")
	)
	(segment
		(start 364.091982 -233.831638)
		(end 364.092236 -233.831892)
		(width 0.0889)
		(layer "B.Cu")
		(net "H_CPU0_MEMHOT_OUT_LVC1_R_N")
	)
	(segment
		(start 378.189236 -233.831892)
		(end 378.233178 -233.806492)
		(width 0.0889)
		(layer "B.Cu")
		(net "H_CPU0_MEMHOT_OUT_LVC1_R_N")
	)
	(segment
		(start 371.044978 -233.831892)
		(end 371.055392 -233.837988)
		(width 0.0889)
		(layer "B.Cu")
		(net "H_CPU0_MEMHOT_OUT_LVC1_R_N")
	)
	(segment
		(start 375.744232 -233.831892)
		(end 375.758964 -233.840528)
		(width 0.0889)
		(layer "B.Cu")
		(net "H_CPU0_MEMHOT_OUT_LVC1_R_N")
	)
	(segment
		(start 367.286032 -233.831892)
		(end 367.300764 -233.840528)
		(width 0.0889)
		(layer "B.Cu")
		(net "H_CPU0_MEMHOT_OUT_LVC1_R_N")
	)
	(arc
		(start 369.165378 -233.831892)
		(mid 369.442191 -233.907728)
		(end 369.720622 -233.837988)
		(width 0.0889)
		(layer "B.Cu")
		(net "H_CPU0_MEMHOT_OUT_LVC1_R_N")
	)
	(arc
		(start 380.068836 -233.831892)
		(mid 380.256034 -233.781749)
		(end 380.443232 -233.831892)
		(width 0.0889)
		(layer "B.Cu")
		(net "H_CPU0_MEMHOT_OUT_LVC1_R_N")
	)
	(arc
		(start 376.694446 -233.837988)
		(mid 376.972624 -233.90768)
		(end 377.249182 -233.831892)
		(width 0.0889)
		(layer "B.Cu")
		(net "H_CPU0_MEMHOT_OUT_LVC1_R_N")
	)
	(arc
		(start 370.115846 -233.837988)
		(mid 370.394024 -233.90768)
		(end 370.670582 -233.831892)
		(width 0.0889)
		(layer "B.Cu")
		(net "H_CPU0_MEMHOT_OUT_LVC1_R_N")
	)
	(arc
		(start 380.443232 -233.831892)
		(mid 380.725934 -233.907634)
		(end 381.008636 -233.831892)
		(width 0.0889)
		(layer "B.Cu")
		(net "H_CPU0_MEMHOT_OUT_LVC1_R_N")
	)
	(arc
		(start 364.481364 -233.840528)
		(mid 364.757805 -233.907694)
		(end 365.032036 -233.831892)
		(width 0.0889)
		(layer "B.Cu")
		(net "H_CPU0_MEMHOT_OUT_LVC1_R_N")
	)
	(arc
		(start 383.846324 -233.821478)
		(mid 384.026061 -233.781314)
		(end 384.203194 -233.831638)
		(width 0.0889)
		(layer "B.Cu")
		(net "H_CPU0_MEMHOT_OUT_LVC1_R_N")
	)
	(arc
		(start 379.518164 -233.840528)
		(mid 379.794605 -233.907694)
		(end 380.068836 -233.831892)
		(width 0.0889)
		(layer "B.Cu")
		(net "H_CPU0_MEMHOT_OUT_LVC1_R_N")
	)
	(arc
		(start 368.790982 -233.831892)
		(mid 368.97818 -233.781749)
		(end 369.165378 -233.831892)
		(width 0.0889)
		(layer "B.Cu")
		(net "H_CPU0_MEMHOT_OUT_LVC1_R_N")
	)
	(arc
		(start 370.670582 -233.831892)
		(mid 370.85778 -233.781749)
		(end 371.044978 -233.831892)
		(width 0.0889)
		(layer "B.Cu")
		(net "H_CPU0_MEMHOT_OUT_LVC1_R_N")
	)
	(arc
		(start 371.610636 -233.831892)
		(mid 371.797834 -233.781749)
		(end 371.985032 -233.831892)
		(width 0.0889)
		(layer "B.Cu")
		(net "H_CPU0_MEMHOT_OUT_LVC1_R_N")
	)
	(arc
		(start 367.851436 -233.831892)
		(mid 368.038634 -233.781749)
		(end 368.225832 -233.831892)
		(width 0.0889)
		(layer "B.Cu")
		(net "H_CPU0_MEMHOT_OUT_LVC1_R_N")
	)
	(arc
		(start 371.055392 -233.837988)
		(mid 371.333824 -233.907802)
		(end 371.610636 -233.831892)
		(width 0.0889)
		(layer "B.Cu")
		(net "H_CPU0_MEMHOT_OUT_LVC1_R_N")
	)
	(arc
		(start 364.092236 -233.831892)
		(mid 364.279434 -233.781749)
		(end 364.466632 -233.831892)
		(width 0.0889)
		(layer "B.Cu")
		(net "H_CPU0_MEMHOT_OUT_LVC1_R_N")
	)
	(arc
		(start 371.999764 -233.840528)
		(mid 372.276205 -233.907694)
		(end 372.550436 -233.831892)
		(width 0.0889)
		(layer "B.Cu")
		(net "H_CPU0_MEMHOT_OUT_LVC1_R_N")
	)
	(arc
		(start 374.430036 -233.831892)
		(mid 374.617234 -233.781749)
		(end 374.804432 -233.831892)
		(width 0.0889)
		(layer "B.Cu")
		(net "H_CPU0_MEMHOT_OUT_LVC1_R_N")
	)
	(arc
		(start 383.262632 -233.831892)
		(mid 383.545334 -233.907634)
		(end 383.828036 -233.831892)
		(width 0.0889)
		(layer "B.Cu")
		(net "H_CPU0_MEMHOT_OUT_LVC1_R_N")
	)
	(arc
		(start 366.911636 -233.831892)
		(mid 367.098724 -233.781715)
		(end 367.285778 -233.831892)
		(width 0.0889)
		(layer "B.Cu")
		(net "H_CPU0_MEMHOT_OUT_LVC1_R_N")
	)
	(arc
		(start 369.731036 -233.831892)
		(mid 369.918234 -233.781749)
		(end 370.105432 -233.831892)
		(width 0.0889)
		(layer "B.Cu")
		(net "H_CPU0_MEMHOT_OUT_LVC1_R_N")
	)
	(arc
		(start 373.490236 -233.831892)
		(mid 373.677434 -233.781749)
		(end 373.864632 -233.831892)
		(width 0.0889)
		(layer "B.Cu")
		(net "H_CPU0_MEMHOT_OUT_LVC1_R_N")
	)
	(arc
		(start 378.233178 -233.806492)
		(mid 378.410978 -233.75887)
		(end 378.588778 -233.806492)
		(width 0.0889)
		(layer "B.Cu")
		(net "H_CPU0_MEMHOT_OUT_LVC1_R_N")
	)
	(arc
		(start 377.249182 -233.831892)
		(mid 377.43638 -233.781749)
		(end 377.623578 -233.831892)
		(width 0.0889)
		(layer "B.Cu")
		(net "H_CPU0_MEMHOT_OUT_LVC1_R_N")
	)
	(arc
		(start 368.236246 -233.837988)
		(mid 368.514424 -233.90768)
		(end 368.790982 -233.831892)
		(width 0.0889)
		(layer "B.Cu")
		(net "H_CPU0_MEMHOT_OUT_LVC1_R_N")
	)
	(arc
		(start 365.032036 -233.831892)
		(mid 365.219234 -233.781749)
		(end 365.406432 -233.831892)
		(width 0.0889)
		(layer "B.Cu")
		(net "H_CPU0_MEMHOT_OUT_LVC1_R_N")
	)
	(arc
		(start 376.309636 -233.831892)
		(mid 376.496834 -233.781749)
		(end 376.684032 -233.831892)
		(width 0.0889)
		(layer "B.Cu")
		(net "H_CPU0_MEMHOT_OUT_LVC1_R_N")
	)
	(arc
		(start 374.819164 -233.840528)
		(mid 375.095605 -233.907694)
		(end 375.369836 -233.831892)
		(width 0.0889)
		(layer "B.Cu")
		(net "H_CPU0_MEMHOT_OUT_LVC1_R_N")
	)
	(arc
		(start 381.948436 -233.831892)
		(mid 382.135634 -233.781749)
		(end 382.322832 -233.831892)
		(width 0.0889)
		(layer "B.Cu")
		(net "H_CPU0_MEMHOT_OUT_LVC1_R_N")
	)
	(arc
		(start 365.971836 -233.831892)
		(mid 366.159034 -233.781749)
		(end 366.346232 -233.831892)
		(width 0.0889)
		(layer "B.Cu")
		(net "H_CPU0_MEMHOT_OUT_LVC1_R_N")
	)
	(arc
		(start 367.300764 -233.840528)
		(mid 367.577205 -233.907694)
		(end 367.851436 -233.831892)
		(width 0.0889)
		(layer "B.Cu")
		(net "H_CPU0_MEMHOT_OUT_LVC1_R_N")
	)
	(arc
		(start 382.888236 -233.831892)
		(mid 383.075434 -233.781749)
		(end 383.262632 -233.831892)
		(width 0.0889)
		(layer "B.Cu")
		(net "H_CPU0_MEMHOT_OUT_LVC1_R_N")
	)
	(arc
		(start 375.369836 -233.831892)
		(mid 375.557034 -233.781749)
		(end 375.744232 -233.831892)
		(width 0.0889)
		(layer "B.Cu")
		(net "H_CPU0_MEMHOT_OUT_LVC1_R_N")
	)
	(arc
		(start 372.939564 -233.840528)
		(mid 373.216005 -233.907694)
		(end 373.490236 -233.831892)
		(width 0.0889)
		(layer "B.Cu")
		(net "H_CPU0_MEMHOT_OUT_LVC1_R_N")
	)
	(arc
		(start 378.68098 -233.84002)
		(mid 378.896657 -233.873409)
		(end 379.112018 -233.837988)
		(width 0.0889)
		(layer "B.Cu")
		(net "H_CPU0_MEMHOT_OUT_LVC1_R_N")
	)
	(arc
		(start 372.550436 -233.831892)
		(mid 372.737634 -233.781749)
		(end 372.924832 -233.831892)
		(width 0.0889)
		(layer "B.Cu")
		(net "H_CPU0_MEMHOT_OUT_LVC1_R_N")
	)
	(arc
		(start 379.140466 -233.825288)
		(mid 379.322801 -233.781691)
		(end 379.503432 -233.831892)
		(width 0.0889)
		(layer "B.Cu")
		(net "H_CPU0_MEMHOT_OUT_LVC1_R_N")
	)
	(arc
		(start 379.112018 -233.837988)
		(mid 379.126511 -233.83224)
		(end 379.140466 -233.825288)
		(width 0.0889)
		(layer "B.Cu")
		(net "H_CPU0_MEMHOT_OUT_LVC1_R_N")
	)
	(arc
		(start 365.421164 -233.840528)
		(mid 365.697605 -233.907694)
		(end 365.971836 -233.831892)
		(width 0.0889)
		(layer "B.Cu")
		(net "H_CPU0_MEMHOT_OUT_LVC1_R_N")
	)
	(arc
		(start 366.360964 -233.840528)
		(mid 366.637405 -233.907694)
		(end 366.911636 -233.831892)
		(width 0.0889)
		(layer "B.Cu")
		(net "H_CPU0_MEMHOT_OUT_LVC1_R_N")
	)
	(arc
		(start 377.633992 -233.837988)
		(mid 377.912424 -233.907802)
		(end 378.189236 -233.831892)
		(width 0.0889)
		(layer "B.Cu")
		(net "H_CPU0_MEMHOT_OUT_LVC1_R_N")
	)
	(arc
		(start 373.864632 -233.831892)
		(mid 374.147334 -233.907634)
		(end 374.430036 -233.831892)
		(width 0.0889)
		(layer "B.Cu")
		(net "H_CPU0_MEMHOT_OUT_LVC1_R_N")
	)
	(arc
		(start 375.758964 -233.840528)
		(mid 376.035405 -233.907694)
		(end 376.309636 -233.831892)
		(width 0.0889)
		(layer "B.Cu")
		(net "H_CPU0_MEMHOT_OUT_LVC1_R_N")
	)
	(arc
		(start 381.383032 -233.831892)
		(mid 381.665734 -233.907634)
		(end 381.948436 -233.831892)
		(width 0.0889)
		(layer "B.Cu")
		(net "H_CPU0_MEMHOT_OUT_LVC1_R_N")
	)
	(arc
		(start 382.322832 -233.831892)
		(mid 382.605534 -233.907634)
		(end 382.888236 -233.831892)
		(width 0.0889)
		(layer "B.Cu")
		(net "H_CPU0_MEMHOT_OUT_LVC1_R_N")
	)
	(arc
		(start 381.008636 -233.831892)
		(mid 381.195834 -233.781749)
		(end 381.383032 -233.831892)
		(width 0.0889)
		(layer "B.Cu")
		(net "H_CPU0_MEMHOT_OUT_LVC1_R_N")
	)
	(segment
		(start 131.24688 -123.243848)
		(end 131.24688 -107.991148)
		(width 0.127)
		(layer "In2.Cu")
		(net "H_CPU0_MEMHOT_OUT_LVC1_R_N")
	)
	(segment
		(start 131.24688 -107.991148)
		(end 131.5212 -107.716828)
		(width 0.127)
		(layer "In2.Cu")
		(net "H_CPU0_MEMHOT_OUT_LVC1_R_N")
	)
	(segment
		(start 127.69088 -93.690948)
		(end 129.72288 -91.658948)
		(width 0.127)
		(layer "In2.Cu")
		(net "H_CPU0_MEMHOT_OUT_LVC1_R_N")
	)
	(segment
		(start 131.5212 -107.716828)
		(end 131.5212 -105.285794)
		(width 0.127)
		(layer "In2.Cu")
		(net "H_CPU0_MEMHOT_OUT_LVC1_R_N")
	)
	(segment
		(start 130.85699 -101.683058)
		(end 127.69088 -98.516948)
		(width 0.127)
		(layer "In2.Cu")
		(net "H_CPU0_MEMHOT_OUT_LVC1_R_N")
	)
	(segment
		(start 131.31038 -150.607268)
		(end 131.52628 -150.391368)
		(width 0.127)
		(layer "In2.Cu")
		(net "H_CPU0_MEMHOT_OUT_LVC1_R_N")
	)
	(segment
		(start 131.52628 -123.523248)
		(end 131.24688 -123.243848)
		(width 0.127)
		(layer "In2.Cu")
		(net "H_CPU0_MEMHOT_OUT_LVC1_R_N")
	)
	(segment
		(start 127.69088 -98.516948)
		(end 127.69088 -93.690948)
		(width 0.127)
		(layer "In2.Cu")
		(net "H_CPU0_MEMHOT_OUT_LVC1_R_N")
	)
	(segment
		(start 130.85699 -104.621584)
		(end 130.85699 -101.683058)
		(width 0.127)
		(layer "In2.Cu")
		(net "H_CPU0_MEMHOT_OUT_LVC1_R_N")
	)
	(segment
		(start 131.52628 -150.391368)
		(end 131.52628 -123.523248)
		(width 0.127)
		(layer "In2.Cu")
		(net "H_CPU0_MEMHOT_OUT_LVC1_R_N")
	)
	(segment
		(start 131.5212 -105.285794)
		(end 130.85699 -104.621584)
		(width 0.127)
		(layer "In2.Cu")
		(net "H_CPU0_MEMHOT_OUT_LVC1_R_N")
	)
	(segment
		(start 216.717118 -155.014168)
		(end 208.241138 -163.490148)
		(width 0.127)
		(layer "In13.Cu")
		(net "H_CPU0_MEMHOT_OUT_LVC1_R_N")
	)
	(segment
		(start 131.7117 -151.008588)
		(end 131.31038 -150.607268)
		(width 0.127)
		(layer "In13.Cu")
		(net "H_CPU0_MEMHOT_OUT_LVC1_R_N")
	)
	(segment
		(start 263.83488 -150.840948)
		(end 263.83488 -151.856948)
		(width 0.127)
		(layer "In13.Cu")
		(net "H_CPU0_MEMHOT_OUT_LVC1_R_N")
	)
	(segment
		(start 142.29842 -148.370798)
		(end 141.20495 -149.464268)
		(width 0.127)
		(layer "In13.Cu")
		(net "H_CPU0_MEMHOT_OUT_LVC1_R_N")
	)
	(segment
		(start 208.241138 -163.490148)
		(end 184.581038 -163.490148)
		(width 0.127)
		(layer "In13.Cu")
		(net "H_CPU0_MEMHOT_OUT_LVC1_R_N")
	)
	(segment
		(start 137.2616 -151.072088)
		(end 136.83234 -150.642828)
		(width 0.127)
		(layer "In13.Cu")
		(net "H_CPU0_MEMHOT_OUT_LVC1_R_N")
	)
	(segment
		(start 141.08938 -149.464268)
		(end 139.48156 -151.072088)
		(width 0.127)
		(layer "In13.Cu")
		(net "H_CPU0_MEMHOT_OUT_LVC1_R_N")
	)
	(segment
		(start 139.48156 -151.072088)
		(end 137.2616 -151.072088)
		(width 0.127)
		(layer "In13.Cu")
		(net "H_CPU0_MEMHOT_OUT_LVC1_R_N")
	)
	(segment
		(start 264.34288 -152.364948)
		(end 264.34288 -153.126948)
		(width 0.127)
		(layer "In13.Cu")
		(net "H_CPU0_MEMHOT_OUT_LVC1_R_N")
	)
	(segment
		(start 262.45566 -155.014168)
		(end 216.717118 -155.014168)
		(width 0.127)
		(layer "In13.Cu")
		(net "H_CPU0_MEMHOT_OUT_LVC1_R_N")
	)
	(segment
		(start 264.34288 -150.332948)
		(end 263.83488 -150.840948)
		(width 0.127)
		(layer "In13.Cu")
		(net "H_CPU0_MEMHOT_OUT_LVC1_R_N")
	)
	(segment
		(start 263.83488 -151.856948)
		(end 264.34288 -152.364948)
		(width 0.127)
		(layer "In13.Cu")
		(net "H_CPU0_MEMHOT_OUT_LVC1_R_N")
	)
	(segment
		(start 136.83234 -150.642828)
		(end 134.89178 -150.642828)
		(width 0.127)
		(layer "In13.Cu")
		(net "H_CPU0_MEMHOT_OUT_LVC1_R_N")
	)
	(segment
		(start 143.891 -145.545048)
		(end 142.29842 -147.137628)
		(width 0.127)
		(layer "In13.Cu")
		(net "H_CPU0_MEMHOT_OUT_LVC1_R_N")
	)
	(segment
		(start 134.89178 -150.642828)
		(end 134.52602 -151.008588)
		(width 0.127)
		(layer "In13.Cu")
		(net "H_CPU0_MEMHOT_OUT_LVC1_R_N")
	)
	(segment
		(start 170.898058 -149.807168)
		(end 151.927306 -149.807168)
		(width 0.127)
		(layer "In13.Cu")
		(net "H_CPU0_MEMHOT_OUT_LVC1_R_N")
	)
	(segment
		(start 147.665186 -145.545048)
		(end 143.891 -145.545048)
		(width 0.127)
		(layer "In13.Cu")
		(net "H_CPU0_MEMHOT_OUT_LVC1_R_N")
	)
	(segment
		(start 151.927306 -149.807168)
		(end 147.665186 -145.545048)
		(width 0.127)
		(layer "In13.Cu")
		(net "H_CPU0_MEMHOT_OUT_LVC1_R_N")
	)
	(segment
		(start 142.29842 -147.137628)
		(end 142.29842 -148.370798)
		(width 0.127)
		(layer "In13.Cu")
		(net "H_CPU0_MEMHOT_OUT_LVC1_R_N")
	)
	(segment
		(start 134.52602 -151.008588)
		(end 131.7117 -151.008588)
		(width 0.127)
		(layer "In13.Cu")
		(net "H_CPU0_MEMHOT_OUT_LVC1_R_N")
	)
	(segment
		(start 184.581038 -163.490148)
		(end 170.898058 -149.807168)
		(width 0.127)
		(layer "In13.Cu")
		(net "H_CPU0_MEMHOT_OUT_LVC1_R_N")
	)
	(segment
		(start 264.34288 -153.126948)
		(end 262.45566 -155.014168)
		(width 0.127)
		(layer "In13.Cu")
		(net "H_CPU0_MEMHOT_OUT_LVC1_R_N")
	)
	(segment
		(start 141.20495 -149.464268)
		(end 141.08938 -149.464268)
		(width 0.127)
		(layer "In13.Cu")
		(net "H_CPU0_MEMHOT_OUT_LVC1_R_N")
	)
	(segment
		(start 131.75488 -87.379048)
		(end 131.75488 -92.274898)
		(width 0.12954)
		(layer "F.Cu")
		(net "H_CPU0_MEMHOT_OUT_LVC1_N")
	)
	(segment
		(start 128.81864 -84.442808)
		(end 131.75488 -87.379048)
		(width 0.12954)
		(layer "F.Cu")
		(net "H_CPU0_MEMHOT_OUT_LVC1_N")
	)
	(segment
		(start 182.155592 -106.575352)
		(end 182.555642 -106.175302)
		(width 0.12954)
		(layer "F.Cu")
		(net "H_CPU0_MEMHOT_OUT_LVC1_N")
	)
	(via
		(at 182.555642 -106.175302)
		(size 0.4572)
		(drill 0.254)
		(layers "F.Cu" "B.Cu")
		(net "H_CPU0_MEMHOT_OUT_LVC1_N")
	)
	(via
		(at 128.81864 -84.442808)
		(size 0.508)
		(drill 0.254)
		(layers "F.Cu" "B.Cu")
		(net "H_CPU0_MEMHOT_OUT_LVC1_N")
	)
	(segment
		(start 165.5572 -95.443548)
		(end 158.90494 -95.443548)
		(width 0.127)
		(layer "In15.Cu")
		(net "H_CPU0_MEMHOT_OUT_LVC1_N")
	)
	(segment
		(start 157.704536 -96.643952)
		(end 153.503884 -96.643952)
		(width 0.127)
		(layer "In15.Cu")
		(net "H_CPU0_MEMHOT_OUT_LVC1_N")
	)
	(segment
		(start 174.298102 -95.8469)
		(end 165.984428 -95.8469)
		(width 0.127)
		(layer "In15.Cu")
		(net "H_CPU0_MEMHOT_OUT_LVC1_N")
	)
	(segment
		(start 165.97249 -95.858838)
		(end 165.5572 -95.443548)
		(width 0.127)
		(layer "In15.Cu")
		(net "H_CPU0_MEMHOT_OUT_LVC1_N")
	)
	(segment
		(start 180.60924 -99.433888)
		(end 180.60924 -98.465386)
		(width 0.127)
		(layer "In15.Cu")
		(net "H_CPU0_MEMHOT_OUT_LVC1_N")
	)
	(segment
		(start 182.14848 -100.973128)
		(end 180.60924 -99.433888)
		(width 0.127)
		(layer "In15.Cu")
		(net "H_CPU0_MEMHOT_OUT_LVC1_N")
	)
	(segment
		(start 176.907952 -95.8596)
		(end 176.907698 -95.8596)
		(width 0.127)
		(layer "In15.Cu")
		(net "H_CPU0_MEMHOT_OUT_LVC1_N")
	)
	(segment
		(start 182.555642 -106.175302)
		(end 182.14848 -105.76814)
		(width 0.127)
		(layer "In15.Cu")
		(net "H_CPU0_MEMHOT_OUT_LVC1_N")
	)
	(segment
		(start 180.271674 -97.602548)
		(end 178.6509 -97.602548)
		(width 0.127)
		(layer "In15.Cu")
		(net "H_CPU0_MEMHOT_OUT_LVC1_N")
	)
	(segment
		(start 129.50952 -83.751928)
		(end 128.81864 -84.442808)
		(width 0.127)
		(layer "In15.Cu")
		(net "H_CPU0_MEMHOT_OUT_LVC1_N")
	)
	(segment
		(start 165.984428 -95.8469)
		(end 165.97249 -95.858838)
		(width 0.127)
		(layer "In15.Cu")
		(net "H_CPU0_MEMHOT_OUT_LVC1_N")
	)
	(segment
		(start 178.6509 -97.602548)
		(end 176.907952 -95.8596)
		(width 0.127)
		(layer "In15.Cu")
		(net "H_CPU0_MEMHOT_OUT_LVC1_N")
	)
	(segment
		(start 180.63464 -98.018854)
		(end 180.60924 -97.993454)
		(width 0.127)
		(layer "In15.Cu")
		(net "H_CPU0_MEMHOT_OUT_LVC1_N")
	)
	(segment
		(start 143.21028 -85.659468)
		(end 141.76248 -85.659468)
		(width 0.127)
		(layer "In15.Cu")
		(net "H_CPU0_MEMHOT_OUT_LVC1_N")
	)
	(segment
		(start 180.63464 -98.439986)
		(end 180.63464 -98.018854)
		(width 0.127)
		(layer "In15.Cu")
		(net "H_CPU0_MEMHOT_OUT_LVC1_N")
	)
	(segment
		(start 150.2918 -92.740988)
		(end 143.21028 -85.659468)
		(width 0.127)
		(layer "In15.Cu")
		(net "H_CPU0_MEMHOT_OUT_LVC1_N")
	)
	(segment
		(start 141.76248 -85.659468)
		(end 139.85494 -83.751928)
		(width 0.127)
		(layer "In15.Cu")
		(net "H_CPU0_MEMHOT_OUT_LVC1_N")
	)
	(segment
		(start 153.503884 -96.643952)
		(end 150.2918 -93.431868)
		(width 0.127)
		(layer "In15.Cu")
		(net "H_CPU0_MEMHOT_OUT_LVC1_N")
	)
	(segment
		(start 180.60924 -97.940114)
		(end 180.271674 -97.602548)
		(width 0.127)
		(layer "In15.Cu")
		(net "H_CPU0_MEMHOT_OUT_LVC1_N")
	)
	(segment
		(start 139.85494 -83.751928)
		(end 129.50952 -83.751928)
		(width 0.127)
		(layer "In15.Cu")
		(net "H_CPU0_MEMHOT_OUT_LVC1_N")
	)
	(segment
		(start 180.60924 -97.993454)
		(end 180.60924 -97.940114)
		(width 0.127)
		(layer "In15.Cu")
		(net "H_CPU0_MEMHOT_OUT_LVC1_N")
	)
	(segment
		(start 176.907698 -95.8596)
		(end 176.898046 -95.849948)
		(width 0.127)
		(layer "In15.Cu")
		(net "H_CPU0_MEMHOT_OUT_LVC1_N")
	)
	(segment
		(start 150.2918 -93.431868)
		(end 150.2918 -92.740988)
		(width 0.127)
		(layer "In15.Cu")
		(net "H_CPU0_MEMHOT_OUT_LVC1_N")
	)
	(segment
		(start 174.30115 -95.849948)
		(end 174.298102 -95.8469)
		(width 0.127)
		(layer "In15.Cu")
		(net "H_CPU0_MEMHOT_OUT_LVC1_N")
	)
	(segment
		(start 176.898046 -95.849948)
		(end 174.30115 -95.849948)
		(width 0.127)
		(layer "In15.Cu")
		(net "H_CPU0_MEMHOT_OUT_LVC1_N")
	)
	(segment
		(start 182.14848 -105.76814)
		(end 182.14848 -100.973128)
		(width 0.127)
		(layer "In15.Cu")
		(net "H_CPU0_MEMHOT_OUT_LVC1_N")
	)
	(segment
		(start 158.90494 -95.443548)
		(end 157.704536 -96.643952)
		(width 0.127)
		(layer "In15.Cu")
		(net "H_CPU0_MEMHOT_OUT_LVC1_N")
	)
	(segment
		(start 180.60924 -98.465386)
		(end 180.63464 -98.439986)
		(width 0.127)
		(layer "In15.Cu")
		(net "H_CPU0_MEMHOT_OUT_LVC1_N")
	)
	(segment
		(start 181.15788 -100.19792)
		(end 181.15788 -100.059998)
		(width 0.12954)
		(layer "F.Cu")
		(net "H_CPU0_MEMHOT_IN_LVC1_R_N")
	)
	(segment
		(start 180.6448 -100.711)
		(end 181.15788 -100.19792)
		(width 0.12954)
		(layer "F.Cu")
		(net "H_CPU0_MEMHOT_IN_LVC1_R_N")
	)
	(segment
		(start 182.155592 -109.775498)
		(end 182.555642 -109.375448)
		(width 0.12954)
		(layer "F.Cu")
		(net "H_CPU0_MEMHOT_IN_LVC1_R_N")
	)
	(via
		(at 182.555642 -109.375448)
		(size 0.4572)
		(drill 0.254)
		(layers "F.Cu" "B.Cu")
		(net "H_CPU0_MEMHOT_IN_LVC1_R_N")
	)
	(via
		(at 180.6448 -100.711)
		(size 0.508)
		(drill 0.254)
		(layers "F.Cu" "B.Cu")
		(net "H_CPU0_MEMHOT_IN_LVC1_R_N")
	)
	(segment
		(start 182.15356 -108.773214)
		(end 182.555642 -109.175296)
		(width 0.127)
		(layer "In11.Cu")
		(net "H_CPU0_MEMHOT_IN_LVC1_R_N")
	)
	(segment
		(start 182.15356 -101.671628)
		(end 182.15356 -108.773214)
		(width 0.127)
		(layer "In11.Cu")
		(net "H_CPU0_MEMHOT_IN_LVC1_R_N")
	)
	(segment
		(start 180.6448 -100.711)
		(end 180.6702 -100.711)
		(width 0.127)
		(layer "In11.Cu")
		(net "H_CPU0_MEMHOT_IN_LVC1_R_N")
	)
	(segment
		(start 181.18328 -100.701348)
		(end 182.15356 -101.671628)
		(width 0.127)
		(layer "In11.Cu")
		(net "H_CPU0_MEMHOT_IN_LVC1_R_N")
	)
	(segment
		(start 182.555642 -109.175296)
		(end 182.555642 -109.375448)
		(width 0.127)
		(layer "In11.Cu")
		(net "H_CPU0_MEMHOT_IN_LVC1_R_N")
	)
	(segment
		(start 180.6702 -100.711)
		(end 180.679852 -100.701348)
		(width 0.127)
		(layer "In11.Cu")
		(net "H_CPU0_MEMHOT_IN_LVC1_R_N")
	)
	(segment
		(start 180.679852 -100.701348)
		(end 181.18328 -100.701348)
		(width 0.127)
		(layer "In11.Cu")
		(net "H_CPU0_MEMHOT_IN_LVC1_R_N")
	)
	(segment
		(start 349.71228 -230.622348)
		(end 349.71228 -230.086662)
		(width 0.12954)
		(layer "F.Cu")
		(net "H_CPU0_MEMHOT_IN_LVC1_N")
	)
	(segment
		(start 349.712534 -230.622602)
		(end 349.71228 -230.622348)
		(width 0.12954)
		(layer "F.Cu")
		(net "H_CPU0_MEMHOT_IN_LVC1_N")
	)
	(segment
		(start 180.01488 -96.23552)
		(end 180.1876 -96.0628)
		(width 0.12954)
		(layer "F.Cu")
		(net "H_CPU0_MEMHOT_IN_LVC1_N")
	)
	(segment
		(start 180.01488 -96.719898)
		(end 180.01488 -96.23552)
		(width 0.12954)
		(layer "F.Cu")
		(net "H_CPU0_MEMHOT_IN_LVC1_N")
	)
	(via
		(at 180.1876 -96.0628)
		(size 0.508)
		(drill 0.254)
		(layers "F.Cu" "B.Cu")
		(net "H_CPU0_MEMHOT_IN_LVC1_N")
	)
	(via
		(at 202.11288 -156.174948)
		(size 0.508)
		(drill 0.254)
		(layers "F.Cu" "B.Cu")
		(net "H_CPU0_MEMHOT_IN_LVC1_N")
	)
	(via
		(at 192.28308 -134.737348)
		(size 0.508)
		(drill 0.254)
		(layers "F.Cu" "B.Cu")
		(net "H_CPU0_MEMHOT_IN_LVC1_N")
	)
	(via
		(at 258.15544 -151.049228)
		(size 0.508)
		(drill 0.254)
		(layers "F.Cu" "B.Cu")
		(net "H_CPU0_MEMHOT_IN_LVC1_N")
	)
	(via
		(at 321.20078 -226.379786)
		(size 0.6604)
		(drill 0.3302)
		(layers "F.Cu" "B.Cu")
		(net "H_CPU0_MEMHOT_IN_LVC1_N")
	)
	(via
		(at 349.71228 -230.086662)
		(size 0.4572)
		(drill 0.2032)
		(layers "F.Cu" "B.Cu")
		(net "H_CPU0_MEMHOT_IN_LVC1_N")
	)
	(segment
		(start 347.645482 -230.41102)
		(end 347.63075 -230.402384)
		(width 0.0889)
		(layer "B.Cu")
		(net "H_CPU0_MEMHOT_IN_LVC1_N")
	)
	(segment
		(start 349.71228 -230.086662)
		(end 349.1484 -230.342948)
		(width 0.0889)
		(layer "B.Cu")
		(net "H_CPU0_MEMHOT_IN_LVC1_N")
	)
	(segment
		(start 325.091044 -230.27005)
		(end 321.20078 -226.379786)
		(width 0.12954)
		(layer "B.Cu")
		(net "H_CPU0_MEMHOT_IN_LVC1_N")
	)
	(segment
		(start 345.211146 -230.404924)
		(end 345.200732 -230.41102)
		(width 0.0889)
		(layer "B.Cu")
		(net "H_CPU0_MEMHOT_IN_LVC1_N")
	)
	(segment
		(start 315.37656 -194.611752)
		(end 314.771278 -194.00647)
		(width 0.12954)
		(layer "B.Cu")
		(net "H_CPU0_MEMHOT_IN_LVC1_N")
	)
	(segment
		(start 315.47054 -198.13651)
		(end 315.37656 -198.04253)
		(width 0.12954)
		(layer "B.Cu")
		(net "H_CPU0_MEMHOT_IN_LVC1_N")
	)
	(segment
		(start 336.085688 -230.335328)
		(end 335.266284 -230.335328)
		(width 0.0889)
		(layer "B.Cu")
		(net "H_CPU0_MEMHOT_IN_LVC1_N")
	)
	(segment
		(start 340.127082 -230.41102)
		(end 340.11235 -230.402384)
		(width 0.0889)
		(layer "B.Cu")
		(net "H_CPU0_MEMHOT_IN_LVC1_N")
	)
	(segment
		(start 346.705682 -230.41102)
		(end 346.69095 -230.402384)
		(width 0.0889)
		(layer "B.Cu")
		(net "H_CPU0_MEMHOT_IN_LVC1_N")
	)
	(segment
		(start 337.307682 -230.41102)
		(end 337.29295 -230.402384)
		(width 0.0889)
		(layer "B.Cu")
		(net "H_CPU0_MEMHOT_IN_LVC1_N")
	)
	(segment
		(start 343.886282 -230.41102)
		(end 343.87155 -230.402384)
		(width 0.0889)
		(layer "B.Cu")
		(net "H_CPU0_MEMHOT_IN_LVC1_N")
	)
	(segment
		(start 321.20078 -226.379786)
		(end 315.47054 -220.649546)
		(width 0.12954)
		(layer "B.Cu")
		(net "H_CPU0_MEMHOT_IN_LVC1_N")
	)
	(segment
		(start 341.066882 -230.41102)
		(end 341.05215 -230.402384)
		(width 0.0889)
		(layer "B.Cu")
		(net "H_CPU0_MEMHOT_IN_LVC1_N")
	)
	(segment
		(start 329.721718 -230.470456)
		(end 329.521312 -230.27005)
		(width 0.12954)
		(layer "B.Cu")
		(net "H_CPU0_MEMHOT_IN_LVC1_N")
	)
	(segment
		(start 258.15544 -158.217108)
		(end 258.15544 -151.049228)
		(width 0.12954)
		(layer "B.Cu")
		(net "H_CPU0_MEMHOT_IN_LVC1_N")
	)
	(segment
		(start 342.006682 -230.41102)
		(end 341.99195 -230.402384)
		(width 0.0889)
		(layer "B.Cu")
		(net "H_CPU0_MEMHOT_IN_LVC1_N")
	)
	(segment
		(start 314.771278 -187.79871)
		(end 302.598836 -175.626268)
		(width 0.12954)
		(layer "B.Cu")
		(net "H_CPU0_MEMHOT_IN_LVC1_N")
	)
	(segment
		(start 344.826336 -230.41102)
		(end 344.815922 -230.404924)
		(width 0.0889)
		(layer "B.Cu")
		(net "H_CPU0_MEMHOT_IN_LVC1_N")
	)
	(segment
		(start 314.771278 -194.00647)
		(end 314.771278 -187.79871)
		(width 0.12954)
		(layer "B.Cu")
		(net "H_CPU0_MEMHOT_IN_LVC1_N")
	)
	(segment
		(start 335.266284 -230.335328)
		(end 335.131156 -230.470456)
		(width 0.12954)
		(layer "B.Cu")
		(net "H_CPU0_MEMHOT_IN_LVC1_N")
	)
	(segment
		(start 335.131156 -230.470456)
		(end 329.721718 -230.470456)
		(width 0.12954)
		(layer "B.Cu")
		(net "H_CPU0_MEMHOT_IN_LVC1_N")
	)
	(segment
		(start 275.5646 -175.626268)
		(end 258.15544 -158.217108)
		(width 0.12954)
		(layer "B.Cu")
		(net "H_CPU0_MEMHOT_IN_LVC1_N")
	)
	(segment
		(start 342.946482 -230.41102)
		(end 342.93175 -230.402384)
		(width 0.0889)
		(layer "B.Cu")
		(net "H_CPU0_MEMHOT_IN_LVC1_N")
	)
	(segment
		(start 338.632546 -230.404924)
		(end 338.622132 -230.41102)
		(width 0.0889)
		(layer "B.Cu")
		(net "H_CPU0_MEMHOT_IN_LVC1_N")
	)
	(segment
		(start 315.47054 -220.649546)
		(end 315.47054 -198.13651)
		(width 0.12954)
		(layer "B.Cu")
		(net "H_CPU0_MEMHOT_IN_LVC1_N")
	)
	(segment
		(start 338.247736 -230.41102)
		(end 338.237322 -230.404924)
		(width 0.0889)
		(layer "B.Cu")
		(net "H_CPU0_MEMHOT_IN_LVC1_N")
	)
	(segment
		(start 348.585282 -230.41102)
		(end 348.57055 -230.402384)
		(width 0.0889)
		(layer "B.Cu")
		(net "H_CPU0_MEMHOT_IN_LVC1_N")
	)
	(segment
		(start 329.521312 -230.27005)
		(end 325.091044 -230.27005)
		(width 0.12954)
		(layer "B.Cu")
		(net "H_CPU0_MEMHOT_IN_LVC1_N")
	)
	(segment
		(start 302.598836 -175.626268)
		(end 275.5646 -175.626268)
		(width 0.12954)
		(layer "B.Cu")
		(net "H_CPU0_MEMHOT_IN_LVC1_N")
	)
	(segment
		(start 315.37656 -198.04253)
		(end 315.37656 -194.611752)
		(width 0.12954)
		(layer "B.Cu")
		(net "H_CPU0_MEMHOT_IN_LVC1_N")
	)
	(arc
		(start 349.1484 -230.342948)
		(mid 349.050998 -230.368551)
		(end 348.959678 -230.41102)
		(width 0.0889)
		(layer "B.Cu")
		(net "H_CPU0_MEMHOT_IN_LVC1_N")
	)
	(arc
		(start 338.237322 -230.404924)
		(mid 337.95889 -230.335078)
		(end 337.682078 -230.41102)
		(width 0.0889)
		(layer "B.Cu")
		(net "H_CPU0_MEMHOT_IN_LVC1_N")
	)
	(arc
		(start 346.140278 -230.41102)
		(mid 345.95308 -230.461163)
		(end 345.765882 -230.41102)
		(width 0.0889)
		(layer "B.Cu")
		(net "H_CPU0_MEMHOT_IN_LVC1_N")
	)
	(arc
		(start 336.742278 -230.41102)
		(mid 336.55508 -230.461163)
		(end 336.367882 -230.41102)
		(width 0.0889)
		(layer "B.Cu")
		(net "H_CPU0_MEMHOT_IN_LVC1_N")
	)
	(arc
		(start 345.765882 -230.41102)
		(mid 345.489323 -230.335277)
		(end 345.211146 -230.404924)
		(width 0.0889)
		(layer "B.Cu")
		(net "H_CPU0_MEMHOT_IN_LVC1_N")
	)
	(arc
		(start 347.63075 -230.402384)
		(mid 347.354275 -230.335064)
		(end 347.080078 -230.41102)
		(width 0.0889)
		(layer "B.Cu")
		(net "H_CPU0_MEMHOT_IN_LVC1_N")
	)
	(arc
		(start 340.11235 -230.402384)
		(mid 339.835875 -230.335064)
		(end 339.561678 -230.41102)
		(width 0.0889)
		(layer "B.Cu")
		(net "H_CPU0_MEMHOT_IN_LVC1_N")
	)
	(arc
		(start 337.682078 -230.41102)
		(mid 337.49488 -230.461163)
		(end 337.307682 -230.41102)
		(width 0.0889)
		(layer "B.Cu")
		(net "H_CPU0_MEMHOT_IN_LVC1_N")
	)
	(arc
		(start 342.93175 -230.402384)
		(mid 342.655275 -230.335064)
		(end 342.381078 -230.41102)
		(width 0.0889)
		(layer "B.Cu")
		(net "H_CPU0_MEMHOT_IN_LVC1_N")
	)
	(arc
		(start 343.320878 -230.41102)
		(mid 343.13368 -230.461163)
		(end 342.946482 -230.41102)
		(width 0.0889)
		(layer "B.Cu")
		(net "H_CPU0_MEMHOT_IN_LVC1_N")
	)
	(arc
		(start 342.381078 -230.41102)
		(mid 342.19388 -230.461163)
		(end 342.006682 -230.41102)
		(width 0.0889)
		(layer "B.Cu")
		(net "H_CPU0_MEMHOT_IN_LVC1_N")
	)
	(arc
		(start 340.501478 -230.41102)
		(mid 340.31428 -230.461163)
		(end 340.127082 -230.41102)
		(width 0.0889)
		(layer "B.Cu")
		(net "H_CPU0_MEMHOT_IN_LVC1_N")
	)
	(arc
		(start 341.05215 -230.402384)
		(mid 340.775675 -230.335064)
		(end 340.501478 -230.41102)
		(width 0.0889)
		(layer "B.Cu")
		(net "H_CPU0_MEMHOT_IN_LVC1_N")
	)
	(arc
		(start 348.57055 -230.402384)
		(mid 348.294075 -230.335064)
		(end 348.019878 -230.41102)
		(width 0.0889)
		(layer "B.Cu")
		(net "H_CPU0_MEMHOT_IN_LVC1_N")
	)
	(arc
		(start 346.69095 -230.402384)
		(mid 346.414475 -230.335064)
		(end 346.140278 -230.41102)
		(width 0.0889)
		(layer "B.Cu")
		(net "H_CPU0_MEMHOT_IN_LVC1_N")
	)
	(arc
		(start 336.367882 -230.41102)
		(mid 336.249251 -230.3595)
		(end 336.12201 -230.336344)
		(width 0.0889)
		(layer "B.Cu")
		(net "H_CPU0_MEMHOT_IN_LVC1_N")
	)
	(arc
		(start 345.200732 -230.41102)
		(mid 345.013534 -230.461163)
		(end 344.826336 -230.41102)
		(width 0.0889)
		(layer "B.Cu")
		(net "H_CPU0_MEMHOT_IN_LVC1_N")
	)
	(arc
		(start 341.99195 -230.402384)
		(mid 341.715475 -230.335064)
		(end 341.441278 -230.41102)
		(width 0.0889)
		(layer "B.Cu")
		(net "H_CPU0_MEMHOT_IN_LVC1_N")
	)
	(arc
		(start 339.561678 -230.41102)
		(mid 339.37448 -230.461163)
		(end 339.187282 -230.41102)
		(width 0.0889)
		(layer "B.Cu")
		(net "H_CPU0_MEMHOT_IN_LVC1_N")
	)
	(arc
		(start 336.12201 -230.336344)
		(mid 336.103857 -230.335541)
		(end 336.085688 -230.335328)
		(width 0.0889)
		(layer "B.Cu")
		(net "H_CPU0_MEMHOT_IN_LVC1_N")
	)
	(arc
		(start 348.019878 -230.41102)
		(mid 347.83268 -230.461163)
		(end 347.645482 -230.41102)
		(width 0.0889)
		(layer "B.Cu")
		(net "H_CPU0_MEMHOT_IN_LVC1_N")
	)
	(arc
		(start 341.441278 -230.41102)
		(mid 341.25408 -230.461163)
		(end 341.066882 -230.41102)
		(width 0.0889)
		(layer "B.Cu")
		(net "H_CPU0_MEMHOT_IN_LVC1_N")
	)
	(arc
		(start 347.080078 -230.41102)
		(mid 346.89288 -230.461163)
		(end 346.705682 -230.41102)
		(width 0.0889)
		(layer "B.Cu")
		(net "H_CPU0_MEMHOT_IN_LVC1_N")
	)
	(arc
		(start 344.815922 -230.404924)
		(mid 344.53749 -230.335078)
		(end 344.260678 -230.41102)
		(width 0.0889)
		(layer "B.Cu")
		(net "H_CPU0_MEMHOT_IN_LVC1_N")
	)
	(arc
		(start 339.187282 -230.41102)
		(mid 338.910723 -230.335277)
		(end 338.632546 -230.404924)
		(width 0.0889)
		(layer "B.Cu")
		(net "H_CPU0_MEMHOT_IN_LVC1_N")
	)
	(arc
		(start 338.622132 -230.41102)
		(mid 338.434934 -230.461163)
		(end 338.247736 -230.41102)
		(width 0.0889)
		(layer "B.Cu")
		(net "H_CPU0_MEMHOT_IN_LVC1_N")
	)
	(arc
		(start 348.959678 -230.41102)
		(mid 348.77248 -230.461163)
		(end 348.585282 -230.41102)
		(width 0.0889)
		(layer "B.Cu")
		(net "H_CPU0_MEMHOT_IN_LVC1_N")
	)
	(arc
		(start 337.29295 -230.402384)
		(mid 337.016475 -230.335064)
		(end 336.742278 -230.41102)
		(width 0.0889)
		(layer "B.Cu")
		(net "H_CPU0_MEMHOT_IN_LVC1_N")
	)
	(arc
		(start 343.87155 -230.402384)
		(mid 343.595075 -230.335064)
		(end 343.320878 -230.41102)
		(width 0.0889)
		(layer "B.Cu")
		(net "H_CPU0_MEMHOT_IN_LVC1_N")
	)
	(arc
		(start 344.260678 -230.41102)
		(mid 344.07348 -230.461163)
		(end 343.886282 -230.41102)
		(width 0.0889)
		(layer "B.Cu")
		(net "H_CPU0_MEMHOT_IN_LVC1_N")
	)
	(segment
		(start 193.40068 -134.076948)
		(end 192.68948 -134.076948)
		(width 0.127)
		(layer "In2.Cu")
		(net "H_CPU0_MEMHOT_IN_LVC1_N")
	)
	(segment
		(start 193.83248 -134.508748)
		(end 193.40068 -134.076948)
		(width 0.127)
		(layer "In2.Cu")
		(net "H_CPU0_MEMHOT_IN_LVC1_N")
	)
	(segment
		(start 202.11288 -156.174948)
		(end 202.11288 -155.216352)
		(width 0.127)
		(layer "In2.Cu")
		(net "H_CPU0_MEMHOT_IN_LVC1_N")
	)
	(segment
		(start 205.16088 -147.269708)
		(end 193.83248 -135.941308)
		(width 0.127)
		(layer "In2.Cu")
		(net "H_CPU0_MEMHOT_IN_LVC1_N")
	)
	(segment
		(start 192.68948 -134.076948)
		(end 192.28308 -134.483348)
		(width 0.127)
		(layer "In2.Cu")
		(net "H_CPU0_MEMHOT_IN_LVC1_N")
	)
	(segment
		(start 202.11288 -155.216352)
		(end 206.30388 -151.025352)
		(width 0.127)
		(layer "In2.Cu")
		(net "H_CPU0_MEMHOT_IN_LVC1_N")
	)
	(segment
		(start 205.16088 -149.443948)
		(end 205.16088 -147.269708)
		(width 0.127)
		(layer "In2.Cu")
		(net "H_CPU0_MEMHOT_IN_LVC1_N")
	)
	(segment
		(start 192.28308 -134.483348)
		(end 192.28308 -134.737348)
		(width 0.127)
		(layer "In2.Cu")
		(net "H_CPU0_MEMHOT_IN_LVC1_N")
	)
	(segment
		(start 193.83248 -135.941308)
		(end 193.83248 -134.508748)
		(width 0.127)
		(layer "In2.Cu")
		(net "H_CPU0_MEMHOT_IN_LVC1_N")
	)
	(segment
		(start 206.30388 -151.025352)
		(end 206.30388 -150.586948)
		(width 0.127)
		(layer "In2.Cu")
		(net "H_CPU0_MEMHOT_IN_LVC1_N")
	)
	(segment
		(start 206.30388 -150.586948)
		(end 205.16088 -149.443948)
		(width 0.127)
		(layer "In2.Cu")
		(net "H_CPU0_MEMHOT_IN_LVC1_N")
	)
	(segment
		(start 189.99708 -116.563648)
		(end 189.99708 -128.116076)
		(width 0.127)
		(layer "In11.Cu")
		(net "H_CPU0_MEMHOT_IN_LVC1_N")
	)
	(segment
		(start 182.35168 -99.837748)
		(end 184.99328 -99.837748)
		(width 0.127)
		(layer "In11.Cu")
		(net "H_CPU0_MEMHOT_IN_LVC1_N")
	)
	(segment
		(start 185.67908 -100.523548)
		(end 185.67908 -104.181148)
		(width 0.127)
		(layer "In11.Cu")
		(net "H_CPU0_MEMHOT_IN_LVC1_N")
	)
	(segment
		(start 191.30518 -133.759448)
		(end 192.28308 -134.737348)
		(width 0.127)
		(layer "In11.Cu")
		(net "H_CPU0_MEMHOT_IN_LVC1_N")
	)
	(segment
		(start 191.11214 -115.448588)
		(end 189.99708 -116.563648)
		(width 0.127)
		(layer "In11.Cu")
		(net "H_CPU0_MEMHOT_IN_LVC1_N")
	)
	(segment
		(start 184.99328 -99.837748)
		(end 185.67908 -100.523548)
		(width 0.127)
		(layer "In11.Cu")
		(net "H_CPU0_MEMHOT_IN_LVC1_N")
	)
	(segment
		(start 191.30518 -129.424176)
		(end 191.30518 -133.759448)
		(width 0.127)
		(layer "In11.Cu")
		(net "H_CPU0_MEMHOT_IN_LVC1_N")
	)
	(segment
		(start 189.99708 -128.116076)
		(end 191.30518 -129.424176)
		(width 0.127)
		(layer "In11.Cu")
		(net "H_CPU0_MEMHOT_IN_LVC1_N")
	)
	(segment
		(start 180.1876 -96.0628)
		(end 180.1876 -96.901)
		(width 0.127)
		(layer "In11.Cu")
		(net "H_CPU0_MEMHOT_IN_LVC1_N")
	)
	(segment
		(start 180.1876 -96.901)
		(end 181.78526 -98.49866)
		(width 0.127)
		(layer "In11.Cu")
		(net "H_CPU0_MEMHOT_IN_LVC1_N")
	)
	(segment
		(start 191.11214 -109.614208)
		(end 191.11214 -115.448588)
		(width 0.127)
		(layer "In11.Cu")
		(net "H_CPU0_MEMHOT_IN_LVC1_N")
	)
	(segment
		(start 181.78526 -98.49866)
		(end 181.78526 -99.271328)
		(width 0.127)
		(layer "In11.Cu")
		(net "H_CPU0_MEMHOT_IN_LVC1_N")
	)
	(segment
		(start 181.78526 -99.271328)
		(end 182.35168 -99.837748)
		(width 0.127)
		(layer "In11.Cu")
		(net "H_CPU0_MEMHOT_IN_LVC1_N")
	)
	(segment
		(start 185.67908 -104.181148)
		(end 191.11214 -109.614208)
		(width 0.127)
		(layer "In11.Cu")
		(net "H_CPU0_MEMHOT_IN_LVC1_N")
	)
	(segment
		(start 215.434672 -151.373586)
		(end 210.36661 -156.441648)
		(width 0.127)
		(layer "In13.Cu")
		(net "H_CPU0_MEMHOT_IN_LVC1_N")
	)
	(segment
		(start 253.500128 -151.373586)
		(end 215.434672 -151.373586)
		(width 0.127)
		(layer "In13.Cu")
		(net "H_CPU0_MEMHOT_IN_LVC1_N")
	)
	(segment
		(start 210.36661 -156.441648)
		(end 203.26858 -156.441648)
		(width 0.127)
		(layer "In13.Cu")
		(net "H_CPU0_MEMHOT_IN_LVC1_N")
	)
	(segment
		(start 258.15544 -151.049228)
		(end 257.43408 -150.327868)
		(width 0.127)
		(layer "In13.Cu")
		(net "H_CPU0_MEMHOT_IN_LVC1_N")
	)
	(segment
		(start 203.26858 -156.441648)
		(end 203.00188 -156.174948)
		(width 0.127)
		(layer "In13.Cu")
		(net "H_CPU0_MEMHOT_IN_LVC1_N")
	)
	(segment
		(start 203.00188 -156.174948)
		(end 202.11288 -156.174948)
		(width 0.127)
		(layer "In13.Cu")
		(net "H_CPU0_MEMHOT_IN_LVC1_N")
	)
	(segment
		(start 254.545846 -150.327868)
		(end 253.500128 -151.373586)
		(width 0.127)
		(layer "In13.Cu")
		(net "H_CPU0_MEMHOT_IN_LVC1_N")
	)
	(segment
		(start 257.43408 -150.327868)
		(end 254.545846 -150.327868)
		(width 0.127)
		(layer "In13.Cu")
		(net "H_CPU0_MEMHOT_IN_LVC1_N")
	)
	(segment
		(start 353.00158 -231.436418)
		(end 353.00158 -230.900732)
		(width 0.12954)
		(layer "F.Cu")
		(net "H_CPU0_ERR2_LVC1_R_N")
	)
	(segment
		(start 353.00158 -230.900732)
		(end 353.001834 -230.900478)
		(width 0.12954)
		(layer "F.Cu")
		(net "H_CPU0_ERR2_LVC1_R_N")
	)
	(via
		(at 353.001834 -230.900478)
		(size 0.4572)
		(drill 0.2032)
		(layers "F.Cu" "B.Cu")
		(net "H_CPU0_ERR2_LVC1_R_N")
	)
	(via
		(at 320.790316 -221.883986)
		(size 0.6604)
		(drill 0.3302)
		(layers "F.Cu" "B.Cu")
		(net "H_CPU0_ERR2_LVC1_R_N")
	)
	(segment
		(start 350.935036 -229.597204)
		(end 350.926146 -229.592124)
		(width 0.0889)
		(layer "B.Cu")
		(net "H_CPU0_ERR2_LVC1_R_N")
	)
	(segment
		(start 336.367882 -228.783388)
		(end 336.357468 -228.777292)
		(width 0.0889)
		(layer "B.Cu")
		(net "H_CPU0_ERR2_LVC1_R_N")
	)
	(segment
		(start 345.766136 -228.783388)
		(end 345.755722 -228.777292)
		(width 0.0889)
		(layer "B.Cu")
		(net "H_CPU0_ERR2_LVC1_R_N")
	)
	(segment
		(start 334.982566 -228.833426)
		(end 334.769206 -228.620066)
		(width 0.0889)
		(layer "B.Cu")
		(net "H_CPU0_ERR2_LVC1_R_N")
	)
	(segment
		(start 351.410778 -230.414576)
		(end 351.404682 -230.41102)
		(width 0.0889)
		(layer "B.Cu")
		(net "H_CPU0_ERR2_LVC1_R_N")
	)
	(segment
		(start 340.127082 -228.783388)
		(end 340.116668 -228.777292)
		(width 0.0889)
		(layer "B.Cu")
		(net "H_CPU0_ERR2_LVC1_R_N")
	)
	(segment
		(start 341.066882 -228.783388)
		(end 341.05215 -228.774752)
		(width 0.0889)
		(layer "B.Cu")
		(net "H_CPU0_ERR2_LVC1_R_N")
	)
	(segment
		(start 350.470978 -228.786944)
		(end 350.464882 -228.783388)
		(width 0.0889)
		(layer "B.Cu")
		(net "H_CPU0_ERR2_LVC1_R_N")
	)
	(segment
		(start 350.464882 -228.783388)
		(end 350.45015 -228.774752)
		(width 0.0889)
		(layer "B.Cu")
		(net "H_CPU0_ERR2_LVC1_R_N")
	)
	(segment
		(start 335.615534 -228.833426)
		(end 334.982566 -228.833426)
		(width 0.0889)
		(layer "B.Cu")
		(net "H_CPU0_ERR2_LVC1_R_N")
	)
	(segment
		(start 320.790316 -221.883986)
		(end 317.56604 -218.65971)
		(width 0.12954)
		(layer "B.Cu")
		(net "H_CPU0_ERR2_LVC1_R_N")
	)
	(segment
		(start 317.56604 -218.65971)
		(end 317.56604 -193.93916)
		(width 0.12954)
		(layer "B.Cu")
		(net "H_CPU0_ERR2_LVC1_R_N")
	)
	(segment
		(start 352.630486 -231.001316)
		(end 352.249232 -231.224836)
		(width 0.0889)
		(layer "B.Cu")
		(net "H_CPU0_ERR2_LVC1_R_N")
	)
	(segment
		(start 338.247482 -228.783388)
		(end 338.23275 -228.774752)
		(width 0.0889)
		(layer "B.Cu")
		(net "H_CPU0_ERR2_LVC1_R_N")
	)
	(segment
		(start 330.967334 -228.620066)
		(end 330.234798 -227.88753)
		(width 0.12954)
		(layer "B.Cu")
		(net "H_CPU0_ERR2_LVC1_R_N")
	)
	(segment
		(start 334.769206 -228.620066)
		(end 334.227678 -228.620066)
		(width 0.0889)
		(layer "B.Cu")
		(net "H_CPU0_ERR2_LVC1_R_N")
	)
	(segment
		(start 326.79386 -227.88753)
		(end 320.790316 -221.883986)
		(width 0.12954)
		(layer "B.Cu")
		(net "H_CPU0_ERR2_LVC1_R_N")
	)
	(segment
		(start 334.227678 -228.620066)
		(end 330.967334 -228.620066)
		(width 0.12954)
		(layer "B.Cu")
		(net "H_CPU0_ERR2_LVC1_R_N")
	)
	(segment
		(start 348.585282 -228.783388)
		(end 348.57055 -228.774752)
		(width 0.0889)
		(layer "B.Cu")
		(net "H_CPU0_ERR2_LVC1_R_N")
	)
	(segment
		(start 337.307682 -228.783388)
		(end 337.29295 -228.774752)
		(width 0.0889)
		(layer "B.Cu")
		(net "H_CPU0_ERR2_LVC1_R_N")
	)
	(segment
		(start 346.705682 -228.783388)
		(end 346.695268 -228.777292)
		(width 0.0889)
		(layer "B.Cu")
		(net "H_CPU0_ERR2_LVC1_R_N")
	)
	(segment
		(start 347.645482 -228.783388)
		(end 347.63075 -228.774752)
		(width 0.0889)
		(layer "B.Cu")
		(net "H_CPU0_ERR2_LVC1_R_N")
	)
	(segment
		(start 339.187536 -228.783388)
		(end 339.177122 -228.777292)
		(width 0.0889)
		(layer "B.Cu")
		(net "H_CPU0_ERR2_LVC1_R_N")
	)
	(segment
		(start 344.826082 -228.783388)
		(end 344.81135 -228.774752)
		(width 0.0889)
		(layer "B.Cu")
		(net "H_CPU0_ERR2_LVC1_R_N")
	)
	(segment
		(start 343.886282 -228.783388)
		(end 343.87155 -228.774752)
		(width 0.0889)
		(layer "B.Cu")
		(net "H_CPU0_ERR2_LVC1_R_N")
	)
	(segment
		(start 351.21723 -230.086662)
		(end 351.21723 -230.071168)
		(width 0.0889)
		(layer "B.Cu")
		(net "H_CPU0_ERR2_LVC1_R_N")
	)
	(segment
		(start 330.234798 -227.88753)
		(end 326.79386 -227.88753)
		(width 0.12954)
		(layer "B.Cu")
		(net "H_CPU0_ERR2_LVC1_R_N")
	)
	(segment
		(start 351.404682 -230.41102)
		(end 351.395792 -230.40594)
		(width 0.0889)
		(layer "B.Cu")
		(net "H_CPU0_ERR2_LVC1_R_N")
	)
	(segment
		(start 342.006682 -228.783388)
		(end 341.99195 -228.774752)
		(width 0.0889)
		(layer "B.Cu")
		(net "H_CPU0_ERR2_LVC1_R_N")
	)
	(segment
		(start 351.874836 -231.224836)
		(end 351.865946 -231.219756)
		(width 0.0889)
		(layer "B.Cu")
		(net "H_CPU0_ERR2_LVC1_R_N")
	)
	(arc
		(start 350.747584 -229.272846)
		(mid 350.673593 -228.99328)
		(end 350.470978 -228.786944)
		(width 0.0889)
		(layer "B.Cu")
		(net "H_CPU0_ERR2_LVC1_R_N")
	)
	(arc
		(start 350.926146 -229.592124)
		(mid 350.795232 -229.455764)
		(end 350.747584 -229.272846)
		(width 0.0889)
		(layer "B.Cu")
		(net "H_CPU0_ERR2_LVC1_R_N")
	)
	(arc
		(start 336.742278 -228.783388)
		(mid 336.55508 -228.833531)
		(end 336.367882 -228.783388)
		(width 0.0889)
		(layer "B.Cu")
		(net "H_CPU0_ERR2_LVC1_R_N")
	)
	(arc
		(start 351.865946 -231.219756)
		(mid 351.735032 -231.083396)
		(end 351.687384 -230.900478)
		(width 0.0889)
		(layer "B.Cu")
		(net "H_CPU0_ERR2_LVC1_R_N")
	)
	(arc
		(start 347.080078 -228.783388)
		(mid 346.89288 -228.833531)
		(end 346.705682 -228.783388)
		(width 0.0889)
		(layer "B.Cu")
		(net "H_CPU0_ERR2_LVC1_R_N")
	)
	(arc
		(start 348.57055 -228.774752)
		(mid 348.294075 -228.707432)
		(end 348.019878 -228.783388)
		(width 0.0889)
		(layer "B.Cu")
		(net "H_CPU0_ERR2_LVC1_R_N")
	)
	(arc
		(start 351.21723 -230.071168)
		(mid 351.13786 -229.797434)
		(end 350.935036 -229.597204)
		(width 0.0889)
		(layer "B.Cu")
		(net "H_CPU0_ERR2_LVC1_R_N")
	)
	(arc
		(start 344.260678 -228.783388)
		(mid 344.07348 -228.833531)
		(end 343.886282 -228.783388)
		(width 0.0889)
		(layer "B.Cu")
		(net "H_CPU0_ERR2_LVC1_R_N")
	)
	(arc
		(start 338.621878 -228.783388)
		(mid 338.43468 -228.833531)
		(end 338.247482 -228.783388)
		(width 0.0889)
		(layer "B.Cu")
		(net "H_CPU0_ERR2_LVC1_R_N")
	)
	(arc
		(start 348.959678 -228.783388)
		(mid 348.77248 -228.833531)
		(end 348.585282 -228.783388)
		(width 0.0889)
		(layer "B.Cu")
		(net "H_CPU0_ERR2_LVC1_R_N")
	)
	(arc
		(start 341.441278 -228.783388)
		(mid 341.25408 -228.833531)
		(end 341.066882 -228.783388)
		(width 0.0889)
		(layer "B.Cu")
		(net "H_CPU0_ERR2_LVC1_R_N")
	)
	(arc
		(start 348.019878 -228.783388)
		(mid 347.83268 -228.833531)
		(end 347.645482 -228.783388)
		(width 0.0889)
		(layer "B.Cu")
		(net "H_CPU0_ERR2_LVC1_R_N")
	)
	(arc
		(start 343.87155 -228.774752)
		(mid 343.595075 -228.707432)
		(end 343.320878 -228.783388)
		(width 0.0889)
		(layer "B.Cu")
		(net "H_CPU0_ERR2_LVC1_R_N")
	)
	(arc
		(start 347.63075 -228.774752)
		(mid 347.354275 -228.707432)
		(end 347.080078 -228.783388)
		(width 0.0889)
		(layer "B.Cu")
		(net "H_CPU0_ERR2_LVC1_R_N")
	)
	(arc
		(start 336.357468 -228.777292)
		(mid 336.07929 -228.707569)
		(end 335.802732 -228.783388)
		(width 0.0889)
		(layer "B.Cu")
		(net "H_CPU0_ERR2_LVC1_R_N")
	)
	(arc
		(start 342.381078 -228.783388)
		(mid 342.19388 -228.833531)
		(end 342.006682 -228.783388)
		(width 0.0889)
		(layer "B.Cu")
		(net "H_CPU0_ERR2_LVC1_R_N")
	)
	(arc
		(start 345.200478 -228.783388)
		(mid 345.01328 -228.833531)
		(end 344.826082 -228.783388)
		(width 0.0889)
		(layer "B.Cu")
		(net "H_CPU0_ERR2_LVC1_R_N")
	)
	(arc
		(start 349.899478 -228.783388)
		(mid 349.71228 -228.833531)
		(end 349.525082 -228.783388)
		(width 0.0889)
		(layer "B.Cu")
		(net "H_CPU0_ERR2_LVC1_R_N")
	)
	(arc
		(start 353.001834 -230.900478)
		(mid 352.809438 -230.92614)
		(end 352.630486 -231.001316)
		(width 0.0889)
		(layer "B.Cu")
		(net "H_CPU0_ERR2_LVC1_R_N")
	)
	(arc
		(start 346.140532 -228.783388)
		(mid 345.953334 -228.833531)
		(end 345.766136 -228.783388)
		(width 0.0889)
		(layer "B.Cu")
		(net "H_CPU0_ERR2_LVC1_R_N")
	)
	(arc
		(start 341.05215 -228.774752)
		(mid 340.775675 -228.707432)
		(end 340.501478 -228.783388)
		(width 0.0889)
		(layer "B.Cu")
		(net "H_CPU0_ERR2_LVC1_R_N")
	)
	(arc
		(start 345.755722 -228.777292)
		(mid 345.47729 -228.707446)
		(end 345.200478 -228.783388)
		(width 0.0889)
		(layer "B.Cu")
		(net "H_CPU0_ERR2_LVC1_R_N")
	)
	(arc
		(start 351.687384 -230.900478)
		(mid 351.613393 -230.620912)
		(end 351.410778 -230.414576)
		(width 0.0889)
		(layer "B.Cu")
		(net "H_CPU0_ERR2_LVC1_R_N")
	)
	(arc
		(start 342.946482 -228.783388)
		(mid 342.66378 -228.707612)
		(end 342.381078 -228.783388)
		(width 0.0889)
		(layer "B.Cu")
		(net "H_CPU0_ERR2_LVC1_R_N")
	)
	(arc
		(start 338.23275 -228.774752)
		(mid 337.956275 -228.707432)
		(end 337.682078 -228.783388)
		(width 0.0889)
		(layer "B.Cu")
		(net "H_CPU0_ERR2_LVC1_R_N")
	)
	(arc
		(start 339.177122 -228.777292)
		(mid 338.89869 -228.707446)
		(end 338.621878 -228.783388)
		(width 0.0889)
		(layer "B.Cu")
		(net "H_CPU0_ERR2_LVC1_R_N")
	)
	(arc
		(start 343.320878 -228.783388)
		(mid 343.13368 -228.833531)
		(end 342.946482 -228.783388)
		(width 0.0889)
		(layer "B.Cu")
		(net "H_CPU0_ERR2_LVC1_R_N")
	)
	(arc
		(start 350.45015 -228.774752)
		(mid 350.173675 -228.707432)
		(end 349.899478 -228.783388)
		(width 0.0889)
		(layer "B.Cu")
		(net "H_CPU0_ERR2_LVC1_R_N")
	)
	(arc
		(start 351.395792 -230.40594)
		(mid 351.264878 -230.26958)
		(end 351.21723 -230.086662)
		(width 0.0889)
		(layer "B.Cu")
		(net "H_CPU0_ERR2_LVC1_R_N")
	)
	(arc
		(start 344.81135 -228.774752)
		(mid 344.534875 -228.707432)
		(end 344.260678 -228.783388)
		(width 0.0889)
		(layer "B.Cu")
		(net "H_CPU0_ERR2_LVC1_R_N")
	)
	(arc
		(start 352.249232 -231.224836)
		(mid 352.062034 -231.274979)
		(end 351.874836 -231.224836)
		(width 0.0889)
		(layer "B.Cu")
		(net "H_CPU0_ERR2_LVC1_R_N")
	)
	(arc
		(start 341.99195 -228.774752)
		(mid 341.715475 -228.707432)
		(end 341.441278 -228.783388)
		(width 0.0889)
		(layer "B.Cu")
		(net "H_CPU0_ERR2_LVC1_R_N")
	)
	(arc
		(start 337.682078 -228.783388)
		(mid 337.49488 -228.833531)
		(end 337.307682 -228.783388)
		(width 0.0889)
		(layer "B.Cu")
		(net "H_CPU0_ERR2_LVC1_R_N")
	)
	(arc
		(start 339.561932 -228.783388)
		(mid 339.374734 -228.833531)
		(end 339.187536 -228.783388)
		(width 0.0889)
		(layer "B.Cu")
		(net "H_CPU0_ERR2_LVC1_R_N")
	)
	(arc
		(start 337.29295 -228.774752)
		(mid 337.016475 -228.707432)
		(end 336.742278 -228.783388)
		(width 0.0889)
		(layer "B.Cu")
		(net "H_CPU0_ERR2_LVC1_R_N")
	)
	(arc
		(start 335.802732 -228.783388)
		(mid 335.712425 -228.820717)
		(end 335.615534 -228.833426)
		(width 0.0889)
		(layer "B.Cu")
		(net "H_CPU0_ERR2_LVC1_R_N")
	)
	(arc
		(start 340.116668 -228.777292)
		(mid 339.83849 -228.707569)
		(end 339.561932 -228.783388)
		(width 0.0889)
		(layer "B.Cu")
		(net "H_CPU0_ERR2_LVC1_R_N")
	)
	(arc
		(start 349.525082 -228.783388)
		(mid 349.24238 -228.707612)
		(end 348.959678 -228.783388)
		(width 0.0889)
		(layer "B.Cu")
		(net "H_CPU0_ERR2_LVC1_R_N")
	)
	(arc
		(start 346.695268 -228.777292)
		(mid 346.41709 -228.707569)
		(end 346.140532 -228.783388)
		(width 0.0889)
		(layer "B.Cu")
		(net "H_CPU0_ERR2_LVC1_R_N")
	)
	(arc
		(start 340.501478 -228.783388)
		(mid 340.31428 -228.833531)
		(end 340.127082 -228.783388)
		(width 0.0889)
		(layer "B.Cu")
		(net "H_CPU0_ERR2_LVC1_R_N")
	)
	(segment
		(start 351.12198 -231.436418)
		(end 351.122234 -231.436164)
		(width 0.12954)
		(layer "F.Cu")
		(net "H_CPU0_ERR1_LVC1_R_N")
	)
	(segment
		(start 351.122234 -231.436164)
		(end 351.122234 -230.900478)
		(width 0.12954)
		(layer "F.Cu")
		(net "H_CPU0_ERR1_LVC1_R_N")
	)
	(via
		(at 351.122234 -230.900478)
		(size 0.4572)
		(drill 0.2032)
		(layers "F.Cu" "B.Cu")
		(net "H_CPU0_ERR1_LVC1_R_N")
	)
	(via
		(at 318.716152 -221.8944)
		(size 0.6604)
		(drill 0.3302)
		(layers "F.Cu" "B.Cu")
		(net "H_CPU0_ERR1_LVC1_R_N")
	)
	(segment
		(start 348.500446 -229.591108)
		(end 348.490032 -229.597204)
		(width 0.0889)
		(layer "B.Cu")
		(net "H_CPU0_ERR1_LVC1_R_N")
	)
	(segment
		(start 333.087726 -229.392226)
		(end 332.744826 -229.735126)
		(width 0.12954)
		(layer "B.Cu")
		(net "H_CPU0_ERR1_LVC1_R_N")
	)
	(segment
		(start 325.895462 -229.07371)
		(end 318.716152 -221.8944)
		(width 0.12954)
		(layer "B.Cu")
		(net "H_CPU0_ERR1_LVC1_R_N")
	)
	(segment
		(start 330.845414 -229.735126)
		(end 330.183998 -229.07371)
		(width 0.12954)
		(layer "B.Cu")
		(net "H_CPU0_ERR1_LVC1_R_N")
	)
	(segment
		(start 316.79134 -219.969588)
		(end 316.79134 -197.323202)
		(width 0.12954)
		(layer "B.Cu")
		(net "H_CPU0_ERR1_LVC1_R_N")
	)
	(segment
		(start 349.439992 -229.591108)
		(end 349.429578 -229.597204)
		(width 0.0889)
		(layer "B.Cu")
		(net "H_CPU0_ERR1_LVC1_R_N")
	)
	(segment
		(start 330.183998 -229.07371)
		(end 325.895462 -229.07371)
		(width 0.12954)
		(layer "B.Cu")
		(net "H_CPU0_ERR1_LVC1_R_N")
	)
	(segment
		(start 346.625164 -229.588568)
		(end 346.610432 -229.597204)
		(width 0.0889)
		(layer "B.Cu")
		(net "H_CPU0_ERR1_LVC1_R_N")
	)
	(segment
		(start 351.047558 -230.8479)
		(end 350.62668 -230.551228)
		(width 0.0889)
		(layer "B.Cu")
		(net "H_CPU0_ERR1_LVC1_R_N")
	)
	(segment
		(start 335.855818 -229.64775)
		(end 335.600294 -229.392226)
		(width 0.0889)
		(layer "B.Cu")
		(net "H_CPU0_ERR1_LVC1_R_N")
	)
	(segment
		(start 336.085434 -229.64775)
		(end 335.855818 -229.64775)
		(width 0.0889)
		(layer "B.Cu")
		(net "H_CPU0_ERR1_LVC1_R_N")
	)
	(segment
		(start 350.470978 -230.414576)
		(end 350.464882 -230.41102)
		(width 0.0889)
		(layer "B.Cu")
		(net "H_CPU0_ERR1_LVC1_R_N")
	)
	(segment
		(start 341.921846 -229.591108)
		(end 341.911432 -229.597204)
		(width 0.0889)
		(layer "B.Cu")
		(net "H_CPU0_ERR1_LVC1_R_N")
	)
	(segment
		(start 342.861392 -229.591108)
		(end 342.850978 -229.597204)
		(width 0.0889)
		(layer "B.Cu")
		(net "H_CPU0_ERR1_LVC1_R_N")
	)
	(segment
		(start 318.716152 -221.8944)
		(end 316.79134 -219.969588)
		(width 0.12954)
		(layer "B.Cu")
		(net "H_CPU0_ERR1_LVC1_R_N")
	)
	(segment
		(start 334.156558 -229.392226)
		(end 333.087726 -229.392226)
		(width 0.12954)
		(layer "B.Cu")
		(net "H_CPU0_ERR1_LVC1_R_N")
	)
	(segment
		(start 332.744826 -229.735126)
		(end 330.845414 -229.735126)
		(width 0.12954)
		(layer "B.Cu")
		(net "H_CPU0_ERR1_LVC1_R_N")
	)
	(segment
		(start 340.046564 -229.588568)
		(end 340.031832 -229.597204)
		(width 0.0889)
		(layer "B.Cu")
		(net "H_CPU0_ERR1_LVC1_R_N")
	)
	(segment
		(start 337.227164 -229.588568)
		(end 337.212432 -229.597204)
		(width 0.0889)
		(layer "B.Cu")
		(net "H_CPU0_ERR1_LVC1_R_N")
	)
	(segment
		(start 339.106764 -229.588568)
		(end 339.092032 -229.597204)
		(width 0.0889)
		(layer "B.Cu")
		(net "H_CPU0_ERR1_LVC1_R_N")
	)
	(segment
		(start 345.685364 -229.588568)
		(end 345.670632 -229.597204)
		(width 0.0889)
		(layer "B.Cu")
		(net "H_CPU0_ERR1_LVC1_R_N")
	)
	(segment
		(start 336.287364 -229.588568)
		(end 336.272632 -229.597204)
		(width 0.0889)
		(layer "B.Cu")
		(net "H_CPU0_ERR1_LVC1_R_N")
	)
	(segment
		(start 350.464882 -230.41102)
		(end 350.455992 -230.40594)
		(width 0.0889)
		(layer "B.Cu")
		(net "H_CPU0_ERR1_LVC1_R_N")
	)
	(segment
		(start 316.55004 -197.081902)
		(end 316.55004 -193.93916)
		(width 0.12954)
		(layer "B.Cu")
		(net "H_CPU0_ERR1_LVC1_R_N")
	)
	(segment
		(start 347.564964 -229.588568)
		(end 347.550232 -229.597204)
		(width 0.0889)
		(layer "B.Cu")
		(net "H_CPU0_ERR1_LVC1_R_N")
	)
	(segment
		(start 343.805764 -229.588568)
		(end 343.791032 -229.597204)
		(width 0.0889)
		(layer "B.Cu")
		(net "H_CPU0_ERR1_LVC1_R_N")
	)
	(segment
		(start 335.600294 -229.392226)
		(end 334.156558 -229.392226)
		(width 0.0889)
		(layer "B.Cu")
		(net "H_CPU0_ERR1_LVC1_R_N")
	)
	(segment
		(start 351.122234 -230.900478)
		(end 351.047558 -230.8479)
		(width 0.0889)
		(layer "B.Cu")
		(net "H_CPU0_ERR1_LVC1_R_N")
	)
	(segment
		(start 350.27743 -230.086662)
		(end 350.27743 -230.071168)
		(width 0.0889)
		(layer "B.Cu")
		(net "H_CPU0_ERR1_LVC1_R_N")
	)
	(segment
		(start 340.986364 -229.588568)
		(end 340.971632 -229.597204)
		(width 0.0889)
		(layer "B.Cu")
		(net "H_CPU0_ERR1_LVC1_R_N")
	)
	(segment
		(start 316.79134 -197.323202)
		(end 316.55004 -197.081902)
		(width 0.12954)
		(layer "B.Cu")
		(net "H_CPU0_ERR1_LVC1_R_N")
	)
	(arc
		(start 344.356436 -229.597204)
		(mid 344.082237 -229.521369)
		(end 343.805764 -229.588568)
		(width 0.0889)
		(layer "B.Cu")
		(net "H_CPU0_ERR1_LVC1_R_N")
	)
	(arc
		(start 348.490032 -229.597204)
		(mid 348.302834 -229.647347)
		(end 348.115636 -229.597204)
		(width 0.0889)
		(layer "B.Cu")
		(net "H_CPU0_ERR1_LVC1_R_N")
	)
	(arc
		(start 342.476582 -229.597204)
		(mid 342.200023 -229.521461)
		(end 341.921846 -229.591108)
		(width 0.0889)
		(layer "B.Cu")
		(net "H_CPU0_ERR1_LVC1_R_N")
	)
	(arc
		(start 340.971632 -229.597204)
		(mid 340.784434 -229.647347)
		(end 340.597236 -229.597204)
		(width 0.0889)
		(layer "B.Cu")
		(net "H_CPU0_ERR1_LVC1_R_N")
	)
	(arc
		(start 350.27743 -230.071168)
		(mid 350.19806 -229.797434)
		(end 349.995236 -229.597204)
		(width 0.0889)
		(layer "B.Cu")
		(net "H_CPU0_ERR1_LVC1_R_N")
	)
	(arc
		(start 349.055182 -229.597204)
		(mid 348.778623 -229.521461)
		(end 348.500446 -229.591108)
		(width 0.0889)
		(layer "B.Cu")
		(net "H_CPU0_ERR1_LVC1_R_N")
	)
	(arc
		(start 339.092032 -229.597204)
		(mid 338.904834 -229.647347)
		(end 338.717636 -229.597204)
		(width 0.0889)
		(layer "B.Cu")
		(net "H_CPU0_ERR1_LVC1_R_N")
	)
	(arc
		(start 345.296236 -229.597204)
		(mid 345.013534 -229.521428)
		(end 344.730832 -229.597204)
		(width 0.0889)
		(layer "B.Cu")
		(net "H_CPU0_ERR1_LVC1_R_N")
	)
	(arc
		(start 349.429578 -229.597204)
		(mid 349.24238 -229.647347)
		(end 349.055182 -229.597204)
		(width 0.0889)
		(layer "B.Cu")
		(net "H_CPU0_ERR1_LVC1_R_N")
	)
	(arc
		(start 341.537036 -229.597204)
		(mid 341.262837 -229.521369)
		(end 340.986364 -229.588568)
		(width 0.0889)
		(layer "B.Cu")
		(net "H_CPU0_ERR1_LVC1_R_N")
	)
	(arc
		(start 345.670632 -229.597204)
		(mid 345.483434 -229.647347)
		(end 345.296236 -229.597204)
		(width 0.0889)
		(layer "B.Cu")
		(net "H_CPU0_ERR1_LVC1_R_N")
	)
	(arc
		(start 343.416636 -229.597204)
		(mid 343.139823 -229.521334)
		(end 342.861392 -229.591108)
		(width 0.0889)
		(layer "B.Cu")
		(net "H_CPU0_ERR1_LVC1_R_N")
	)
	(arc
		(start 337.777836 -229.597204)
		(mid 337.503637 -229.521369)
		(end 337.227164 -229.588568)
		(width 0.0889)
		(layer "B.Cu")
		(net "H_CPU0_ERR1_LVC1_R_N")
	)
	(arc
		(start 350.455992 -230.40594)
		(mid 350.325078 -230.26958)
		(end 350.27743 -230.086662)
		(width 0.0889)
		(layer "B.Cu")
		(net "H_CPU0_ERR1_LVC1_R_N")
	)
	(arc
		(start 350.62668 -230.551228)
		(mid 350.555137 -230.475716)
		(end 350.470978 -230.414576)
		(width 0.0889)
		(layer "B.Cu")
		(net "H_CPU0_ERR1_LVC1_R_N")
	)
	(arc
		(start 336.272632 -229.597204)
		(mid 336.18236 -229.634803)
		(end 336.085434 -229.64775)
		(width 0.0889)
		(layer "B.Cu")
		(net "H_CPU0_ERR1_LVC1_R_N")
	)
	(arc
		(start 339.657436 -229.597204)
		(mid 339.383237 -229.521369)
		(end 339.106764 -229.588568)
		(width 0.0889)
		(layer "B.Cu")
		(net "H_CPU0_ERR1_LVC1_R_N")
	)
	(arc
		(start 346.236036 -229.597204)
		(mid 345.961837 -229.521369)
		(end 345.685364 -229.588568)
		(width 0.0889)
		(layer "B.Cu")
		(net "H_CPU0_ERR1_LVC1_R_N")
	)
	(arc
		(start 338.152232 -229.597204)
		(mid 337.965034 -229.647347)
		(end 337.777836 -229.597204)
		(width 0.0889)
		(layer "B.Cu")
		(net "H_CPU0_ERR1_LVC1_R_N")
	)
	(arc
		(start 340.597236 -229.597204)
		(mid 340.323037 -229.521369)
		(end 340.046564 -229.588568)
		(width 0.0889)
		(layer "B.Cu")
		(net "H_CPU0_ERR1_LVC1_R_N")
	)
	(arc
		(start 341.911432 -229.597204)
		(mid 341.724234 -229.647347)
		(end 341.537036 -229.597204)
		(width 0.0889)
		(layer "B.Cu")
		(net "H_CPU0_ERR1_LVC1_R_N")
	)
	(arc
		(start 336.838036 -229.597204)
		(mid 336.563837 -229.521369)
		(end 336.287364 -229.588568)
		(width 0.0889)
		(layer "B.Cu")
		(net "H_CPU0_ERR1_LVC1_R_N")
	)
	(arc
		(start 349.995236 -229.597204)
		(mid 349.718423 -229.521334)
		(end 349.439992 -229.591108)
		(width 0.0889)
		(layer "B.Cu")
		(net "H_CPU0_ERR1_LVC1_R_N")
	)
	(arc
		(start 347.175836 -229.597204)
		(mid 346.901637 -229.521369)
		(end 346.625164 -229.588568)
		(width 0.0889)
		(layer "B.Cu")
		(net "H_CPU0_ERR1_LVC1_R_N")
	)
	(arc
		(start 337.212432 -229.597204)
		(mid 337.025234 -229.647347)
		(end 336.838036 -229.597204)
		(width 0.0889)
		(layer "B.Cu")
		(net "H_CPU0_ERR1_LVC1_R_N")
	)
	(arc
		(start 344.730832 -229.597204)
		(mid 344.543634 -229.647347)
		(end 344.356436 -229.597204)
		(width 0.0889)
		(layer "B.Cu")
		(net "H_CPU0_ERR1_LVC1_R_N")
	)
	(arc
		(start 346.610432 -229.597204)
		(mid 346.423234 -229.647347)
		(end 346.236036 -229.597204)
		(width 0.0889)
		(layer "B.Cu")
		(net "H_CPU0_ERR1_LVC1_R_N")
	)
	(arc
		(start 342.850978 -229.597204)
		(mid 342.66378 -229.647347)
		(end 342.476582 -229.597204)
		(width 0.0889)
		(layer "B.Cu")
		(net "H_CPU0_ERR1_LVC1_R_N")
	)
	(arc
		(start 338.717636 -229.597204)
		(mid 338.434934 -229.521428)
		(end 338.152232 -229.597204)
		(width 0.0889)
		(layer "B.Cu")
		(net "H_CPU0_ERR1_LVC1_R_N")
	)
	(arc
		(start 347.550232 -229.597204)
		(mid 347.363034 -229.647347)
		(end 347.175836 -229.597204)
		(width 0.0889)
		(layer "B.Cu")
		(net "H_CPU0_ERR1_LVC1_R_N")
	)
	(arc
		(start 348.115636 -229.597204)
		(mid 347.841437 -229.521369)
		(end 347.564964 -229.588568)
		(width 0.0889)
		(layer "B.Cu")
		(net "H_CPU0_ERR1_LVC1_R_N")
	)
	(arc
		(start 343.791032 -229.597204)
		(mid 343.603834 -229.647347)
		(end 343.416636 -229.597204)
		(width 0.0889)
		(layer "B.Cu")
		(net "H_CPU0_ERR1_LVC1_R_N")
	)
	(arc
		(start 340.031832 -229.597204)
		(mid 339.844634 -229.647347)
		(end 339.657436 -229.597204)
		(width 0.0889)
		(layer "B.Cu")
		(net "H_CPU0_ERR1_LVC1_R_N")
	)
	(segment
		(start 353.94138 -230.900732)
		(end 353.941634 -230.900478)
		(width 0.12954)
		(layer "F.Cu")
		(net "H_CPU0_ERR0_LVC1_R_N")
	)
	(segment
		(start 353.94138 -231.436418)
		(end 353.94138 -230.900732)
		(width 0.12954)
		(layer "F.Cu")
		(net "H_CPU0_ERR0_LVC1_R_N")
	)
	(via
		(at 353.941634 -230.900478)
		(size 0.4572)
		(drill 0.2032)
		(layers "F.Cu" "B.Cu")
		(net "H_CPU0_ERR0_LVC1_R_N")
	)
	(via
		(at 324.425564 -220.59646)
		(size 0.6604)
		(drill 0.3302)
		(layers "F.Cu" "B.Cu")
		(net "H_CPU0_ERR0_LVC1_R_N")
	)
	(segment
		(start 321.7545 -188.026294)
		(end 321.001898 -187.273692)
		(width 0.12954)
		(layer "B.Cu")
		(net "H_CPU0_ERR0_LVC1_R_N")
	)
	(segment
		(start 351.318322 -228.953568)
		(end 351.309432 -228.948488)
		(width 0.0889)
		(layer "B.Cu")
		(net "H_CPU0_ERR0_LVC1_R_N")
	)
	(segment
		(start 321.7545 -189.402212)
		(end 321.7545 -188.026294)
		(width 0.12954)
		(layer "B.Cu")
		(net "H_CPU0_ERR0_LVC1_R_N")
	)
	(segment
		(start 345.765882 -226.506786)
		(end 345.75115 -226.515422)
		(width 0.0889)
		(layer "B.Cu")
		(net "H_CPU0_ERR0_LVC1_R_N")
	)
	(segment
		(start 351.309432 -228.948488)
		(end 351.303336 -228.944932)
		(width 0.0889)
		(layer "B.Cu")
		(net "H_CPU0_ERR0_LVC1_R_N")
	)
	(segment
		(start 332.185772 -226.456748)
		(end 330.71054 -224.981516)
		(width 0.12954)
		(layer "B.Cu")
		(net "H_CPU0_ERR0_LVC1_R_N")
	)
	(segment
		(start 334.488282 -226.506786)
		(end 334.477868 -226.512882)
		(width 0.0889)
		(layer "B.Cu")
		(net "H_CPU0_ERR0_LVC1_R_N")
	)
	(segment
		(start 349.525082 -226.506786)
		(end 349.514668 -226.512882)
		(width 0.0889)
		(layer "B.Cu")
		(net "H_CPU0_ERR0_LVC1_R_N")
	)
	(segment
		(start 350.378522 -227.325682)
		(end 350.369632 -227.320602)
		(width 0.0889)
		(layer "B.Cu")
		(net "H_CPU0_ERR0_LVC1_R_N")
	)
	(segment
		(start 343.886536 -226.506786)
		(end 343.876122 -226.512882)
		(width 0.0889)
		(layer "B.Cu")
		(net "H_CPU0_ERR0_LVC1_R_N")
	)
	(segment
		(start 352.249232 -230.57612)
		(end 352.243136 -230.572564)
		(width 0.0889)
		(layer "B.Cu")
		(net "H_CPU0_ERR0_LVC1_R_N")
	)
	(segment
		(start 352.263964 -230.584756)
		(end 352.249232 -230.57612)
		(width 0.0889)
		(layer "B.Cu")
		(net "H_CPU0_ERR0_LVC1_R_N")
	)
	(segment
		(start 342.946482 -226.506786)
		(end 342.93175 -226.515422)
		(width 0.0889)
		(layer "B.Cu")
		(net "H_CPU0_ERR0_LVC1_R_N")
	)
	(segment
		(start 349.908368 -226.511866)
		(end 349.899478 -226.506786)
		(width 0.0889)
		(layer "B.Cu")
		(net "H_CPU0_ERR0_LVC1_R_N")
	)
	(segment
		(start 322.939918 -219.110814)
		(end 322.939918 -190.58763)
		(width 0.12954)
		(layer "B.Cu")
		(net "H_CPU0_ERR0_LVC1_R_N")
	)
	(segment
		(start 321.001898 -187.273692)
		(end 321.001898 -186.83986)
		(width 0.12954)
		(layer "B.Cu")
		(net "H_CPU0_ERR0_LVC1_R_N")
	)
	(segment
		(start 332.79588 -226.456748)
		(end 332.485238 -226.456748)
		(width 0.0889)
		(layer "B.Cu")
		(net "H_CPU0_ERR0_LVC1_R_N")
	)
	(segment
		(start 353.941634 -230.900478)
		(end 353.78517 -230.62946)
		(width 0.0889)
		(layer "B.Cu")
		(net "H_CPU0_ERR0_LVC1_R_N")
	)
	(segment
		(start 351.787968 -229.767384)
		(end 351.779078 -229.762304)
		(width 0.0889)
		(layer "B.Cu")
		(net "H_CPU0_ERR0_LVC1_R_N")
	)
	(segment
		(start 332.485238 -226.456748)
		(end 332.185772 -226.456748)
		(width 0.12954)
		(layer "B.Cu")
		(net "H_CPU0_ERR0_LVC1_R_N")
	)
	(segment
		(start 353.78517 -230.62946)
		(end 353.696016 -230.605584)
		(width 0.0889)
		(layer "B.Cu")
		(net "H_CPU0_ERR0_LVC1_R_N")
	)
	(segment
		(start 351.496884 -229.28834)
		(end 351.496884 -229.272846)
		(width 0.0889)
		(layer "B.Cu")
		(net "H_CPU0_ERR0_LVC1_R_N")
	)
	(segment
		(start 328.81062 -224.981516)
		(end 324.425564 -220.59646)
		(width 0.12954)
		(layer "B.Cu")
		(net "H_CPU0_ERR0_LVC1_R_N")
	)
	(segment
		(start 344.826082 -226.506786)
		(end 344.815668 -226.512882)
		(width 0.0889)
		(layer "B.Cu")
		(net "H_CPU0_ERR0_LVC1_R_N")
	)
	(segment
		(start 334.873092 -226.512882)
		(end 334.862678 -226.506786)
		(width 0.0889)
		(layer "B.Cu")
		(net "H_CPU0_ERR0_LVC1_R_N")
	)
	(segment
		(start 322.939918 -190.58763)
		(end 321.7545 -189.402212)
		(width 0.12954)
		(layer "B.Cu")
		(net "H_CPU0_ERR0_LVC1_R_N")
	)
	(segment
		(start 350.848168 -228.139752)
		(end 350.839278 -228.134672)
		(width 0.0889)
		(layer "B.Cu")
		(net "H_CPU0_ERR0_LVC1_R_N")
	)
	(segment
		(start 338.632292 -226.512882)
		(end 338.621878 -226.506786)
		(width 0.0889)
		(layer "B.Cu")
		(net "H_CPU0_ERR0_LVC1_R_N")
	)
	(segment
		(start 346.705936 -226.506786)
		(end 346.695522 -226.512882)
		(width 0.0889)
		(layer "B.Cu")
		(net "H_CPU0_ERR0_LVC1_R_N")
	)
	(segment
		(start 342.006682 -226.506786)
		(end 341.996268 -226.512882)
		(width 0.0889)
		(layer "B.Cu")
		(net "H_CPU0_ERR0_LVC1_R_N")
	)
	(segment
		(start 330.71054 -224.981516)
		(end 328.81062 -224.981516)
		(width 0.12954)
		(layer "B.Cu")
		(net "H_CPU0_ERR0_LVC1_R_N")
	)
	(segment
		(start 350.369632 -227.320602)
		(end 350.363536 -227.317046)
		(width 0.0889)
		(layer "B.Cu")
		(net "H_CPU0_ERR0_LVC1_R_N")
	)
	(segment
		(start 350.557084 -227.667058)
		(end 350.557084 -227.64496)
		(width 0.0889)
		(layer "B.Cu")
		(net "H_CPU0_ERR0_LVC1_R_N")
	)
	(segment
		(start 338.247482 -226.506786)
		(end 338.23275 -226.515422)
		(width 0.0889)
		(layer "B.Cu")
		(net "H_CPU0_ERR0_LVC1_R_N")
	)
	(segment
		(start 336.367882 -226.506786)
		(end 336.357468 -226.512882)
		(width 0.0889)
		(layer "B.Cu")
		(net "H_CPU0_ERR0_LVC1_R_N")
	)
	(segment
		(start 324.425564 -220.59646)
		(end 322.939918 -219.110814)
		(width 0.12954)
		(layer "B.Cu")
		(net "H_CPU0_ERR0_LVC1_R_N")
	)
	(segment
		(start 337.307682 -226.506786)
		(end 337.29295 -226.515422)
		(width 0.0889)
		(layer "B.Cu")
		(net "H_CPU0_ERR0_LVC1_R_N")
	)
	(segment
		(start 332.993492 -226.512882)
		(end 332.983078 -226.506786)
		(width 0.0889)
		(layer "B.Cu")
		(net "H_CPU0_ERR0_LVC1_R_N")
	)
	(segment
		(start 353.203764 -230.584756)
		(end 353.189032 -230.57612)
		(width 0.0889)
		(layer "B.Cu")
		(net "H_CPU0_ERR0_LVC1_R_N")
	)
	(arc
		(start 340.501732 -226.506786)
		(mid 340.314534 -226.456643)
		(end 340.127336 -226.506786)
		(width 0.0889)
		(layer "B.Cu")
		(net "H_CPU0_ERR0_LVC1_R_N")
	)
	(arc
		(start 336.357468 -226.512882)
		(mid 336.07929 -226.582605)
		(end 335.802732 -226.506786)
		(width 0.0889)
		(layer "B.Cu")
		(net "H_CPU0_ERR0_LVC1_R_N")
	)
	(arc
		(start 350.08693 -226.831144)
		(mid 350.039251 -226.648244)
		(end 349.908368 -226.511866)
		(width 0.0889)
		(layer "B.Cu")
		(net "H_CPU0_ERR0_LVC1_R_N")
	)
	(arc
		(start 333.923132 -226.506786)
		(mid 333.735934 -226.456643)
		(end 333.548736 -226.506786)
		(width 0.0889)
		(layer "B.Cu")
		(net "H_CPU0_ERR0_LVC1_R_N")
	)
	(arc
		(start 341.996268 -226.512882)
		(mid 341.71809 -226.582605)
		(end 341.441532 -226.506786)
		(width 0.0889)
		(layer "B.Cu")
		(net "H_CPU0_ERR0_LVC1_R_N")
	)
	(arc
		(start 338.621878 -226.506786)
		(mid 338.43468 -226.456643)
		(end 338.247482 -226.506786)
		(width 0.0889)
		(layer "B.Cu")
		(net "H_CPU0_ERR0_LVC1_R_N")
	)
	(arc
		(start 341.067136 -226.506786)
		(mid 340.784434 -226.582562)
		(end 340.501732 -226.506786)
		(width 0.0889)
		(layer "B.Cu")
		(net "H_CPU0_ERR0_LVC1_R_N")
	)
	(arc
		(start 342.93175 -226.515422)
		(mid 342.655275 -226.582742)
		(end 342.381078 -226.506786)
		(width 0.0889)
		(layer "B.Cu")
		(net "H_CPU0_ERR0_LVC1_R_N")
	)
	(arc
		(start 350.363536 -227.317046)
		(mid 350.160949 -227.110695)
		(end 350.08693 -226.831144)
		(width 0.0889)
		(layer "B.Cu")
		(net "H_CPU0_ERR0_LVC1_R_N")
	)
	(arc
		(start 343.876122 -226.512882)
		(mid 343.59769 -226.582728)
		(end 343.320878 -226.506786)
		(width 0.0889)
		(layer "B.Cu")
		(net "H_CPU0_ERR0_LVC1_R_N")
	)
	(arc
		(start 352.243136 -230.572564)
		(mid 352.040549 -230.366213)
		(end 351.96653 -230.086662)
		(width 0.0889)
		(layer "B.Cu")
		(net "H_CPU0_ERR0_LVC1_R_N")
	)
	(arc
		(start 345.200478 -226.506786)
		(mid 345.01328 -226.456643)
		(end 344.826082 -226.506786)
		(width 0.0889)
		(layer "B.Cu")
		(net "H_CPU0_ERR0_LVC1_R_N")
	)
	(arc
		(start 337.682078 -226.506786)
		(mid 337.49488 -226.456643)
		(end 337.307682 -226.506786)
		(width 0.0889)
		(layer "B.Cu")
		(net "H_CPU0_ERR0_LVC1_R_N")
	)
	(arc
		(start 339.187536 -226.506786)
		(mid 338.910723 -226.582656)
		(end 338.632292 -226.512882)
		(width 0.0889)
		(layer "B.Cu")
		(net "H_CPU0_ERR0_LVC1_R_N")
	)
	(arc
		(start 353.189032 -230.57612)
		(mid 353.001834 -230.525977)
		(end 352.814636 -230.57612)
		(width 0.0889)
		(layer "B.Cu")
		(net "H_CPU0_ERR0_LVC1_R_N")
	)
	(arc
		(start 335.802732 -226.506786)
		(mid 335.615534 -226.456643)
		(end 335.428336 -226.506786)
		(width 0.0889)
		(layer "B.Cu")
		(net "H_CPU0_ERR0_LVC1_R_N")
	)
	(arc
		(start 335.428336 -226.506786)
		(mid 335.151523 -226.582656)
		(end 334.873092 -226.512882)
		(width 0.0889)
		(layer "B.Cu")
		(net "H_CPU0_ERR0_LVC1_R_N")
	)
	(arc
		(start 337.29295 -226.515422)
		(mid 337.016475 -226.582742)
		(end 336.742278 -226.506786)
		(width 0.0889)
		(layer "B.Cu")
		(net "H_CPU0_ERR0_LVC1_R_N")
	)
	(arc
		(start 342.381078 -226.506786)
		(mid 342.19388 -226.456643)
		(end 342.006682 -226.506786)
		(width 0.0889)
		(layer "B.Cu")
		(net "H_CPU0_ERR0_LVC1_R_N")
	)
	(arc
		(start 346.695522 -226.512882)
		(mid 346.41709 -226.582728)
		(end 346.140278 -226.506786)
		(width 0.0889)
		(layer "B.Cu")
		(net "H_CPU0_ERR0_LVC1_R_N")
	)
	(arc
		(start 334.477868 -226.512882)
		(mid 334.19969 -226.582605)
		(end 333.923132 -226.506786)
		(width 0.0889)
		(layer "B.Cu")
		(net "H_CPU0_ERR0_LVC1_R_N")
	)
	(arc
		(start 351.02673 -228.45903)
		(mid 350.979051 -228.27613)
		(end 350.848168 -228.139752)
		(width 0.0889)
		(layer "B.Cu")
		(net "H_CPU0_ERR0_LVC1_R_N")
	)
	(arc
		(start 339.561932 -226.506786)
		(mid 339.374734 -226.456643)
		(end 339.187536 -226.506786)
		(width 0.0889)
		(layer "B.Cu")
		(net "H_CPU0_ERR0_LVC1_R_N")
	)
	(arc
		(start 348.959932 -226.506786)
		(mid 348.772734 -226.456643)
		(end 348.585536 -226.506786)
		(width 0.0889)
		(layer "B.Cu")
		(net "H_CPU0_ERR0_LVC1_R_N")
	)
	(arc
		(start 349.514668 -226.512882)
		(mid 349.23649 -226.582605)
		(end 348.959932 -226.506786)
		(width 0.0889)
		(layer "B.Cu")
		(net "H_CPU0_ERR0_LVC1_R_N")
	)
	(arc
		(start 351.779078 -229.762304)
		(mid 351.576255 -229.562073)
		(end 351.496884 -229.28834)
		(width 0.0889)
		(layer "B.Cu")
		(net "H_CPU0_ERR0_LVC1_R_N")
	)
	(arc
		(start 345.75115 -226.515422)
		(mid 345.474675 -226.582742)
		(end 345.200478 -226.506786)
		(width 0.0889)
		(layer "B.Cu")
		(net "H_CPU0_ERR0_LVC1_R_N")
	)
	(arc
		(start 347.645736 -226.506786)
		(mid 347.363034 -226.582562)
		(end 347.080332 -226.506786)
		(width 0.0889)
		(layer "B.Cu")
		(net "H_CPU0_ERR0_LVC1_R_N")
	)
	(arc
		(start 340.127336 -226.506786)
		(mid 339.844634 -226.582562)
		(end 339.561932 -226.506786)
		(width 0.0889)
		(layer "B.Cu")
		(net "H_CPU0_ERR0_LVC1_R_N")
	)
	(arc
		(start 343.320878 -226.506786)
		(mid 343.13368 -226.456643)
		(end 342.946482 -226.506786)
		(width 0.0889)
		(layer "B.Cu")
		(net "H_CPU0_ERR0_LVC1_R_N")
	)
	(arc
		(start 338.23275 -226.515422)
		(mid 337.956275 -226.582742)
		(end 337.682078 -226.506786)
		(width 0.0889)
		(layer "B.Cu")
		(net "H_CPU0_ERR0_LVC1_R_N")
	)
	(arc
		(start 350.839278 -228.134672)
		(mid 350.637996 -227.937185)
		(end 350.557084 -227.667058)
		(width 0.0889)
		(layer "B.Cu")
		(net "H_CPU0_ERR0_LVC1_R_N")
	)
	(arc
		(start 352.814636 -230.57612)
		(mid 352.540437 -230.651955)
		(end 352.263964 -230.584756)
		(width 0.0889)
		(layer "B.Cu")
		(net "H_CPU0_ERR0_LVC1_R_N")
	)
	(arc
		(start 336.742278 -226.506786)
		(mid 336.55508 -226.456643)
		(end 336.367882 -226.506786)
		(width 0.0889)
		(layer "B.Cu")
		(net "H_CPU0_ERR0_LVC1_R_N")
	)
	(arc
		(start 348.020132 -226.506786)
		(mid 347.832934 -226.456643)
		(end 347.645736 -226.506786)
		(width 0.0889)
		(layer "B.Cu")
		(net "H_CPU0_ERR0_LVC1_R_N")
	)
	(arc
		(start 351.96653 -230.086662)
		(mid 351.918851 -229.903762)
		(end 351.787968 -229.767384)
		(width 0.0889)
		(layer "B.Cu")
		(net "H_CPU0_ERR0_LVC1_R_N")
	)
	(arc
		(start 334.862678 -226.506786)
		(mid 334.67548 -226.456643)
		(end 334.488282 -226.506786)
		(width 0.0889)
		(layer "B.Cu")
		(net "H_CPU0_ERR0_LVC1_R_N")
	)
	(arc
		(start 351.496884 -229.272846)
		(mid 351.449205 -229.089946)
		(end 351.318322 -228.953568)
		(width 0.0889)
		(layer "B.Cu")
		(net "H_CPU0_ERR0_LVC1_R_N")
	)
	(arc
		(start 341.441532 -226.506786)
		(mid 341.254334 -226.456643)
		(end 341.067136 -226.506786)
		(width 0.0889)
		(layer "B.Cu")
		(net "H_CPU0_ERR0_LVC1_R_N")
	)
	(arc
		(start 351.303336 -228.944932)
		(mid 351.100749 -228.738581)
		(end 351.02673 -228.45903)
		(width 0.0889)
		(layer "B.Cu")
		(net "H_CPU0_ERR0_LVC1_R_N")
	)
	(arc
		(start 350.557084 -227.64496)
		(mid 350.509405 -227.46206)
		(end 350.378522 -227.325682)
		(width 0.0889)
		(layer "B.Cu")
		(net "H_CPU0_ERR0_LVC1_R_N")
	)
	(arc
		(start 348.585536 -226.506786)
		(mid 348.302834 -226.582562)
		(end 348.020132 -226.506786)
		(width 0.0889)
		(layer "B.Cu")
		(net "H_CPU0_ERR0_LVC1_R_N")
	)
	(arc
		(start 344.815668 -226.512882)
		(mid 344.53749 -226.582605)
		(end 344.260932 -226.506786)
		(width 0.0889)
		(layer "B.Cu")
		(net "H_CPU0_ERR0_LVC1_R_N")
	)
	(arc
		(start 332.983078 -226.506786)
		(mid 332.892771 -226.469457)
		(end 332.79588 -226.456748)
		(width 0.0889)
		(layer "B.Cu")
		(net "H_CPU0_ERR0_LVC1_R_N")
	)
	(arc
		(start 347.080332 -226.506786)
		(mid 346.893134 -226.456643)
		(end 346.705936 -226.506786)
		(width 0.0889)
		(layer "B.Cu")
		(net "H_CPU0_ERR0_LVC1_R_N")
	)
	(arc
		(start 349.899478 -226.506786)
		(mid 349.71228 -226.456643)
		(end 349.525082 -226.506786)
		(width 0.0889)
		(layer "B.Cu")
		(net "H_CPU0_ERR0_LVC1_R_N")
	)
	(arc
		(start 344.260932 -226.506786)
		(mid 344.073734 -226.456643)
		(end 343.886536 -226.506786)
		(width 0.0889)
		(layer "B.Cu")
		(net "H_CPU0_ERR0_LVC1_R_N")
	)
	(arc
		(start 333.548736 -226.506786)
		(mid 333.271923 -226.582656)
		(end 332.993492 -226.512882)
		(width 0.0889)
		(layer "B.Cu")
		(net "H_CPU0_ERR0_LVC1_R_N")
	)
	(arc
		(start 353.696016 -230.605584)
		(mid 353.447511 -230.651571)
		(end 353.203764 -230.584756)
		(width 0.0889)
		(layer "B.Cu")
		(net "H_CPU0_ERR0_LVC1_R_N")
	)
	(arc
		(start 346.140278 -226.506786)
		(mid 345.95308 -226.456643)
		(end 345.765882 -226.506786)
		(width 0.0889)
		(layer "B.Cu")
		(net "H_CPU0_ERR0_LVC1_R_N")
	)
	(segment
		(start 357.700834 -233.06405)
		(end 357.700834 -232.528364)
		(width 0.12954)
		(layer "F.Cu")
		(net "H_CPU0_CATERR_LVC1_R_N")
	)
	(segment
		(start 357.70058 -233.064304)
		(end 357.700834 -233.06405)
		(width 0.12954)
		(layer "F.Cu")
		(net "H_CPU0_CATERR_LVC1_R_N")
	)
	(via
		(at 330.029058 -194.43065)
		(size 0.6604)
		(drill 0.3302)
		(layers "F.Cu" "B.Cu")
		(net "H_CPU0_CATERR_LVC1_R_N")
	)
	(via
		(at 357.700834 -232.528364)
		(size 0.4572)
		(drill 0.2032)
		(layers "F.Cu" "B.Cu")
		(net "H_CPU0_CATERR_LVC1_R_N")
	)
	(via
		(at 332.53934 -201.371708)
		(size 0.508)
		(drill 0.254)
		(layers "F.Cu" "B.Cu")
		(net "H_CPU0_CATERR_LVC1_R_N")
	)
	(segment
		(start 329.028298 -187.70219)
		(end 329.028298 -186.90844)
		(width 0.12954)
		(layer "B.Cu")
		(net "H_CPU0_CATERR_LVC1_R_N")
	)
	(segment
		(start 329.584558 -188.25845)
		(end 329.028298 -187.70219)
		(width 0.12954)
		(layer "B.Cu")
		(net "H_CPU0_CATERR_LVC1_R_N")
	)
	(segment
		(start 330.88072 -200.516236)
		(end 329.69708 -199.332596)
		(width 0.12954)
		(layer "B.Cu")
		(net "H_CPU0_CATERR_LVC1_R_N")
	)
	(segment
		(start 331.189076 -201.282808)
		(end 330.88072 -200.974452)
		(width 0.12954)
		(layer "B.Cu")
		(net "H_CPU0_CATERR_LVC1_R_N")
	)
	(segment
		(start 329.69708 -199.332596)
		(end 329.534266 -198.940166)
		(width 0.12954)
		(layer "B.Cu")
		(net "H_CPU0_CATERR_LVC1_R_N")
	)
	(segment
		(start 332.45044 -201.282808)
		(end 331.189076 -201.282808)
		(width 0.12954)
		(layer "B.Cu")
		(net "H_CPU0_CATERR_LVC1_R_N")
	)
	(segment
		(start 329.584558 -188.66993)
		(end 329.584558 -188.25845)
		(width 0.12954)
		(layer "B.Cu")
		(net "H_CPU0_CATERR_LVC1_R_N")
	)
	(segment
		(start 330.029058 -196.406516)
		(end 330.029058 -194.43065)
		(width 0.12954)
		(layer "B.Cu")
		(net "H_CPU0_CATERR_LVC1_R_N")
	)
	(segment
		(start 329.534266 -198.940166)
		(end 329.534266 -196.901308)
		(width 0.12954)
		(layer "B.Cu")
		(net "H_CPU0_CATERR_LVC1_R_N")
	)
	(segment
		(start 329.534266 -196.901308)
		(end 330.029058 -196.406516)
		(width 0.12954)
		(layer "B.Cu")
		(net "H_CPU0_CATERR_LVC1_R_N")
	)
	(segment
		(start 332.53934 -201.371708)
		(end 332.45044 -201.282808)
		(width 0.12954)
		(layer "B.Cu")
		(net "H_CPU0_CATERR_LVC1_R_N")
	)
	(segment
		(start 330.029058 -189.11443)
		(end 329.584558 -188.66993)
		(width 0.12954)
		(layer "B.Cu")
		(net "H_CPU0_CATERR_LVC1_R_N")
	)
	(segment
		(start 330.029058 -194.43065)
		(end 330.029058 -189.11443)
		(width 0.12954)
		(layer "B.Cu")
		(net "H_CPU0_CATERR_LVC1_R_N")
	)
	(segment
		(start 329.028298 -186.90844)
		(end 329.170538 -186.7662)
		(width 0.12954)
		(layer "B.Cu")
		(net "H_CPU0_CATERR_LVC1_R_N")
	)
	(segment
		(start 330.88072 -200.974452)
		(end 330.88072 -200.516236)
		(width 0.12954)
		(layer "B.Cu")
		(net "H_CPU0_CATERR_LVC1_R_N")
	)
	(segment
		(start 335.418176 -215.930988)
		(end 335.184242 -215.697054)
		(width 0.0889)
		(layer "In4.Cu")
		(net "H_CPU0_CATERR_LVC1_R_N")
	)
	(segment
		(start 357.79583 -228.474524)
		(end 357.79583 -228.436932)
		(width 0.0889)
		(layer "In4.Cu")
		(net "H_CPU0_CATERR_LVC1_R_N")
	)
	(segment
		(start 357.513636 -227.320602)
		(end 357.519732 -227.317046)
		(width 0.0889)
		(layer "In4.Cu")
		(net "H_CPU0_CATERR_LVC1_R_N")
	)
	(segment
		(start 355.916484 -223.575626)
		(end 355.916484 -223.561402)
		(width 0.0889)
		(layer "In4.Cu")
		(net "H_CPU0_CATERR_LVC1_R_N")
	)
	(segment
		(start 335.184242 -215.697054)
		(end 332.642972 -209.561684)
		(width 0.127)
		(layer "In4.Cu")
		(net "H_CPU0_CATERR_LVC1_R_N")
	)
	(segment
		(start 347.564964 -219.82176)
		(end 347.550232 -219.830396)
		(width 0.0889)
		(layer "In4.Cu")
		(net "H_CPU0_CATERR_LVC1_R_N")
	)
	(segment
		(start 357.519732 -226.345242)
		(end 357.513636 -226.341686)
		(width 0.0889)
		(layer "In4.Cu")
		(net "H_CPU0_CATERR_LVC1_R_N")
	)
	(segment
		(start 335.897982 -216.574878)
		(end 335.82864 -216.534238)
		(width 0.0889)
		(layer "In4.Cu")
		(net "H_CPU0_CATERR_LVC1_R_N")
	)
	(segment
		(start 357.796084 -231.714548)
		(end 357.796084 -231.706928)
		(width 0.0889)
		(layer "In4.Cu")
		(net "H_CPU0_CATERR_LVC1_R_N")
	)
	(segment
		(start 357.513636 -227.969318)
		(end 357.504746 -227.964238)
		(width 0.0889)
		(layer "In4.Cu")
		(net "H_CPU0_CATERR_LVC1_R_N")
	)
	(segment
		(start 349.055436 -221.458282)
		(end 349.046546 -221.453202)
		(width 0.0889)
		(layer "In4.Cu")
		(net "H_CPU0_CATERR_LVC1_R_N")
	)
	(segment
		(start 357.043482 -225.527616)
		(end 357.034592 -225.522536)
		(width 0.0889)
		(layer "In4.Cu")
		(net "H_CPU0_CATERR_LVC1_R_N")
	)
	(segment
		(start 357.326184 -226.017328)
		(end 357.326184 -226.003104)
		(width 0.0889)
		(layer "In4.Cu")
		(net "H_CPU0_CATERR_LVC1_R_N")
	)
	(segment
		(start 357.471726 -230.548688)
		(end 357.664258 -230.35641)
		(width 0.0889)
		(layer "In4.Cu")
		(net "H_CPU0_CATERR_LVC1_R_N")
	)
	(segment
		(start 349.33763 -221.94774)
		(end 349.33763 -221.932246)
		(width 0.0889)
		(layer "In4.Cu")
		(net "H_CPU0_CATERR_LVC1_R_N")
	)
	(segment
		(start 357.664258 -229.93731)
		(end 357.410258 -229.68331)
		(width 0.0889)
		(layer "In4.Cu")
		(net "H_CPU0_CATERR_LVC1_R_N")
	)
	(segment
		(start 347.175836 -219.830396)
		(end 347.166946 -219.825316)
		(width 0.0889)
		(layer "In4.Cu")
		(net "H_CPU0_CATERR_LVC1_R_N")
	)
	(segment
		(start 357.700834 -232.528364)
		(end 357.54437 -232.799382)
		(width 0.0889)
		(layer "In4.Cu")
		(net "H_CPU0_CATERR_LVC1_R_N")
	)
	(segment
		(start 335.82864 -216.534238)
		(end 335.66481 -216.370408)
		(width 0.0889)
		(layer "In4.Cu")
		(net "H_CPU0_CATERR_LVC1_R_N")
	)
	(segment
		(start 336.18043 -217.064336)
		(end 336.18043 -217.05443)
		(width 0.0889)
		(layer "In4.Cu")
		(net "H_CPU0_CATERR_LVC1_R_N")
	)
	(segment
		(start 349.995236 -223.085914)
		(end 349.89897 -223.030288)
		(width 0.0889)
		(layer "In4.Cu")
		(net "H_CPU0_CATERR_LVC1_R_N")
	)
	(segment
		(start 346.711778 -219.020136)
		(end 346.705682 -219.01658)
		(width 0.0889)
		(layer "In4.Cu")
		(net "H_CPU0_CATERR_LVC1_R_N")
	)
	(segment
		(start 339.187282 -219.01658)
		(end 339.17255 -219.007944)
		(width 0.0889)
		(layer "In4.Cu")
		(net "H_CPU0_CATERR_LVC1_R_N")
	)
	(segment
		(start 356.573836 -224.7138)
		(end 356.564946 -224.70872)
		(width 0.0889)
		(layer "In4.Cu")
		(net "H_CPU0_CATERR_LVC1_R_N")
	)
	(segment
		(start 332.642972 -209.561684)
		(end 332.642972 -207.612996)
		(width 0.127)
		(layer "In4.Cu")
		(net "H_CPU0_CATERR_LVC1_R_N")
	)
	(segment
		(start 348.121732 -219.833952)
		(end 348.115636 -219.830396)
		(width 0.0889)
		(layer "In4.Cu")
		(net "H_CPU0_CATERR_LVC1_R_N")
	)
	(segment
		(start 348.585536 -220.644212)
		(end 348.576646 -220.639132)
		(width 0.0889)
		(layer "In4.Cu")
		(net "H_CPU0_CATERR_LVC1_R_N")
	)
	(segment
		(start 348.867984 -221.133924)
		(end 348.867984 -221.115382)
		(width 0.0889)
		(layer "In4.Cu")
		(net "H_CPU0_CATERR_LVC1_R_N")
	)
	(segment
		(start 357.513636 -232.204006)
		(end 357.519732 -232.20045)
		(width 0.0889)
		(layer "In4.Cu")
		(net "H_CPU0_CATERR_LVC1_R_N")
	)
	(segment
		(start 337.120484 -218.700858)
		(end 337.120484 -218.682316)
		(width 0.0889)
		(layer "In4.Cu")
		(net "H_CPU0_CATERR_LVC1_R_N")
	)
	(segment
		(start 336.650584 -217.878406)
		(end 336.650584 -217.864182)
		(width 0.0889)
		(layer "In4.Cu")
		(net "H_CPU0_CATERR_LVC1_R_N")
	)
	(segment
		(start 354.694236 -223.085914)
		(end 354.33889 -223.085914)
		(width 0.0889)
		(layer "In4.Cu")
		(net "H_CPU0_CATERR_LVC1_R_N")
	)
	(segment
		(start 346.705682 -219.01658)
		(end 346.69095 -219.007944)
		(width 0.0889)
		(layer "In4.Cu")
		(net "H_CPU0_CATERR_LVC1_R_N")
	)
	(segment
		(start 332.53934 -201.497946)
		(end 332.53934 -201.371708)
		(width 0.127)
		(layer "In4.Cu")
		(net "H_CPU0_CATERR_LVC1_R_N")
	)
	(segment
		(start 345.765882 -219.01658)
		(end 345.75115 -219.007944)
		(width 0.0889)
		(layer "In4.Cu")
		(net "H_CPU0_CATERR_LVC1_R_N")
	)
	(segment
		(start 356.85603 -225.203258)
		(end 356.85603 -225.187764)
		(width 0.0889)
		(layer "In4.Cu")
		(net "H_CPU0_CATERR_LVC1_R_N")
	)
	(segment
		(start 336.367882 -217.388694)
		(end 336.358992 -217.383614)
		(width 0.0889)
		(layer "In4.Cu")
		(net "H_CPU0_CATERR_LVC1_R_N")
	)
	(segment
		(start 343.886282 -219.01658)
		(end 343.87155 -219.007944)
		(width 0.0889)
		(layer "In4.Cu")
		(net "H_CPU0_CATERR_LVC1_R_N")
	)
	(segment
		(start 342.006682 -219.01658)
		(end 341.99195 -219.007944)
		(width 0.0889)
		(layer "In4.Cu")
		(net "H_CPU0_CATERR_LVC1_R_N")
	)
	(segment
		(start 338.247482 -219.01658)
		(end 338.23275 -219.007944)
		(width 0.0889)
		(layer "In4.Cu")
		(net "H_CPU0_CATERR_LVC1_R_N")
	)
	(segment
		(start 357.54437 -232.799382)
		(end 357.466138 -232.82021)
		(width 0.0889)
		(layer "In4.Cu")
		(net "H_CPU0_CATERR_LVC1_R_N")
	)
	(segment
		(start 357.326184 -229.480364)
		(end 357.326184 -229.272846)
		(width 0.0889)
		(layer "In4.Cu")
		(net "H_CPU0_CATERR_LVC1_R_N")
	)
	(segment
		(start 340.127082 -219.01658)
		(end 340.11235 -219.007944)
		(width 0.0889)
		(layer "In4.Cu")
		(net "H_CPU0_CATERR_LVC1_R_N")
	)
	(segment
		(start 357.504746 -227.325682)
		(end 357.513636 -227.320602)
		(width 0.0889)
		(layer "In4.Cu")
		(net "H_CPU0_CATERR_LVC1_R_N")
	)
	(segment
		(start 351.324164 -223.077278)
		(end 351.309432 -223.085914)
		(width 0.0889)
		(layer "In4.Cu")
		(net "H_CPU0_CATERR_LVC1_R_N")
	)
	(segment
		(start 357.513636 -226.341686)
		(end 357.504746 -226.336606)
		(width 0.0889)
		(layer "In4.Cu")
		(net "H_CPU0_CATERR_LVC1_R_N")
	)
	(segment
		(start 333.049118 -202.007724)
		(end 332.53934 -201.497946)
		(width 0.127)
		(layer "In4.Cu")
		(net "H_CPU0_CATERR_LVC1_R_N")
	)
	(segment
		(start 341.066882 -219.01658)
		(end 341.05215 -219.007944)
		(width 0.0889)
		(layer "In4.Cu")
		(net "H_CPU0_CATERR_LVC1_R_N")
	)
	(segment
		(start 353.203764 -223.077278)
		(end 353.189032 -223.085914)
		(width 0.0889)
		(layer "In4.Cu")
		(net "H_CPU0_CATERR_LVC1_R_N")
	)
	(segment
		(start 349.659702 -222.616014)
		(end 349.582486 -222.538798)
		(width 0.0889)
		(layer "In4.Cu")
		(net "H_CPU0_CATERR_LVC1_R_N")
	)
	(segment
		(start 342.946482 -219.01658)
		(end 342.93175 -219.007944)
		(width 0.0889)
		(layer "In4.Cu")
		(net "H_CPU0_CATERR_LVC1_R_N")
	)
	(segment
		(start 355.083364 -223.077278)
		(end 355.068632 -223.085914)
		(width 0.0889)
		(layer "In4.Cu")
		(net "H_CPU0_CATERR_LVC1_R_N")
	)
	(segment
		(start 332.642972 -207.612996)
		(end 333.049118 -207.20685)
		(width 0.127)
		(layer "In4.Cu")
		(net "H_CPU0_CATERR_LVC1_R_N")
	)
	(segment
		(start 356.386384 -224.389442)
		(end 356.386384 -224.379536)
		(width 0.0889)
		(layer "In4.Cu")
		(net "H_CPU0_CATERR_LVC1_R_N")
	)
	(segment
		(start 357.326184 -230.909114)
		(end 357.326184 -230.900478)
		(width 0.0889)
		(layer "In4.Cu")
		(net "H_CPU0_CATERR_LVC1_R_N")
	)
	(segment
		(start 344.826082 -219.01658)
		(end 344.81135 -219.007944)
		(width 0.0889)
		(layer "In4.Cu")
		(net "H_CPU0_CATERR_LVC1_R_N")
	)
	(segment
		(start 336.838036 -218.202764)
		(end 336.829146 -218.197684)
		(width 0.0889)
		(layer "In4.Cu")
		(net "H_CPU0_CATERR_LVC1_R_N")
	)
	(segment
		(start 357.504746 -232.209086)
		(end 357.513636 -232.204006)
		(width 0.0889)
		(layer "In4.Cu")
		(net "H_CPU0_CATERR_LVC1_R_N")
	)
	(segment
		(start 333.049118 -207.20685)
		(end 333.049118 -202.007724)
		(width 0.127)
		(layer "In4.Cu")
		(net "H_CPU0_CATERR_LVC1_R_N")
	)
	(segment
		(start 356.103936 -223.899984)
		(end 356.095046 -223.894904)
		(width 0.0889)
		(layer "In4.Cu")
		(net "H_CPU0_CATERR_LVC1_R_N")
	)
	(segment
		(start 357.504746 -228.953568)
		(end 357.513636 -228.948488)
		(width 0.0889)
		(layer "In4.Cu")
		(net "H_CPU0_CATERR_LVC1_R_N")
	)
	(segment
		(start 353.868228 -223.1517)
		(end 353.754436 -223.085914)
		(width 0.0889)
		(layer "In4.Cu")
		(net "H_CPU0_CATERR_LVC1_R_N")
	)
	(arc
		(start 357.326184 -226.003104)
		(mid 357.246965 -225.728419)
		(end 357.043482 -225.527616)
		(width 0.0889)
		(layer "In4.Cu")
		(net "H_CPU0_CATERR_LVC1_R_N")
	)
	(arc
		(start 355.068632 -223.085914)
		(mid 354.881434 -223.136057)
		(end 354.694236 -223.085914)
		(width 0.0889)
		(layer "In4.Cu")
		(net "H_CPU0_CATERR_LVC1_R_N")
	)
	(arc
		(start 337.682078 -219.01658)
		(mid 337.49488 -219.066723)
		(end 337.307682 -219.01658)
		(width 0.0889)
		(layer "In4.Cu")
		(net "H_CPU0_CATERR_LVC1_R_N")
	)
	(arc
		(start 349.89897 -223.030288)
		(mid 349.723819 -222.855216)
		(end 349.659702 -222.616014)
		(width 0.0889)
		(layer "In4.Cu")
		(net "H_CPU0_CATERR_LVC1_R_N")
	)
	(arc
		(start 337.307682 -219.01658)
		(mid 337.172749 -218.883226)
		(end 337.120484 -218.700858)
		(width 0.0889)
		(layer "In4.Cu")
		(net "H_CPU0_CATERR_LVC1_R_N")
	)
	(arc
		(start 343.320878 -219.01658)
		(mid 343.13368 -219.066723)
		(end 342.946482 -219.01658)
		(width 0.0889)
		(layer "In4.Cu")
		(net "H_CPU0_CATERR_LVC1_R_N")
	)
	(arc
		(start 348.398084 -220.319854)
		(mid 348.324168 -220.040352)
		(end 348.121732 -219.833952)
		(width 0.0889)
		(layer "In4.Cu")
		(net "H_CPU0_CATERR_LVC1_R_N")
	)
	(arc
		(start 349.582486 -222.538798)
		(mid 349.40129 -222.267618)
		(end 349.33763 -221.94774)
		(width 0.0889)
		(layer "In4.Cu")
		(net "H_CPU0_CATERR_LVC1_R_N")
	)
	(arc
		(start 344.260678 -219.01658)
		(mid 344.07348 -219.066723)
		(end 343.886282 -219.01658)
		(width 0.0889)
		(layer "In4.Cu")
		(net "H_CPU0_CATERR_LVC1_R_N")
	)
	(arc
		(start 347.550232 -219.830396)
		(mid 347.363034 -219.880539)
		(end 347.175836 -219.830396)
		(width 0.0889)
		(layer "In4.Cu")
		(net "H_CPU0_CATERR_LVC1_R_N")
	)
	(arc
		(start 341.05215 -219.007944)
		(mid 340.775675 -218.940624)
		(end 340.501478 -219.01658)
		(width 0.0889)
		(layer "In4.Cu")
		(net "H_CPU0_CATERR_LVC1_R_N")
	)
	(arc
		(start 356.85603 -225.187764)
		(mid 356.77666 -224.91403)
		(end 356.573836 -224.7138)
		(width 0.0889)
		(layer "In4.Cu")
		(net "H_CPU0_CATERR_LVC1_R_N")
	)
	(arc
		(start 357.79583 -228.436932)
		(mid 357.714919 -228.166804)
		(end 357.513636 -227.969318)
		(width 0.0889)
		(layer "In4.Cu")
		(net "H_CPU0_CATERR_LVC1_R_N")
	)
	(arc
		(start 354.33889 -223.085914)
		(mid 354.330919 -223.087499)
		(end 354.324158 -223.09201)
		(width 0.0889)
		(layer "In4.Cu")
		(net "H_CPU0_CATERR_LVC1_R_N")
	)
	(arc
		(start 350.935036 -223.085914)
		(mid 350.652334 -223.010172)
		(end 350.369632 -223.085914)
		(width 0.0889)
		(layer "In4.Cu")
		(net "H_CPU0_CATERR_LVC1_R_N")
	)
	(arc
		(start 357.410258 -229.68331)
		(mid 357.348042 -229.590198)
		(end 357.326184 -229.480364)
		(width 0.0889)
		(layer "In4.Cu")
		(net "H_CPU0_CATERR_LVC1_R_N")
	)
	(arc
		(start 357.326184 -230.900478)
		(mid 357.363958 -230.710104)
		(end 357.471726 -230.548688)
		(width 0.0889)
		(layer "In4.Cu")
		(net "H_CPU0_CATERR_LVC1_R_N")
	)
	(arc
		(start 356.095046 -223.894904)
		(mid 355.964132 -223.758544)
		(end 355.916484 -223.575626)
		(width 0.0889)
		(layer "In4.Cu")
		(net "H_CPU0_CATERR_LVC1_R_N")
	)
	(arc
		(start 344.81135 -219.007944)
		(mid 344.534875 -218.940624)
		(end 344.260678 -219.01658)
		(width 0.0889)
		(layer "In4.Cu")
		(net "H_CPU0_CATERR_LVC1_R_N")
	)
	(arc
		(start 357.326184 -232.528364)
		(mid 357.373863 -232.345464)
		(end 357.504746 -232.209086)
		(width 0.0889)
		(layer "In4.Cu")
		(net "H_CPU0_CATERR_LVC1_R_N")
	)
	(arc
		(start 349.33763 -221.932246)
		(mid 349.25826 -221.658512)
		(end 349.055436 -221.458282)
		(width 0.0889)
		(layer "In4.Cu")
		(net "H_CPU0_CATERR_LVC1_R_N")
	)
	(arc
		(start 338.23275 -219.007944)
		(mid 337.956275 -218.940624)
		(end 337.682078 -219.01658)
		(width 0.0889)
		(layer "In4.Cu")
		(net "H_CPU0_CATERR_LVC1_R_N")
	)
	(arc
		(start 336.358992 -217.383614)
		(mid 336.228078 -217.247254)
		(end 336.18043 -217.064336)
		(width 0.0889)
		(layer "In4.Cu")
		(net "H_CPU0_CATERR_LVC1_R_N")
	)
	(arc
		(start 348.576646 -220.639132)
		(mid 348.445732 -220.502772)
		(end 348.398084 -220.319854)
		(width 0.0889)
		(layer "In4.Cu")
		(net "H_CPU0_CATERR_LVC1_R_N")
	)
	(arc
		(start 340.501478 -219.01658)
		(mid 340.31428 -219.066723)
		(end 340.127082 -219.01658)
		(width 0.0889)
		(layer "In4.Cu")
		(net "H_CPU0_CATERR_LVC1_R_N")
	)
	(arc
		(start 357.513382 -231.224836)
		(mid 357.378449 -231.091482)
		(end 357.326184 -230.909114)
		(width 0.0889)
		(layer "In4.Cu")
		(net "H_CPU0_CATERR_LVC1_R_N")
	)
	(arc
		(start 347.166946 -219.825316)
		(mid 347.036032 -219.688956)
		(end 346.988384 -219.506038)
		(width 0.0889)
		(layer "In4.Cu")
		(net "H_CPU0_CATERR_LVC1_R_N")
	)
	(arc
		(start 348.115636 -219.830396)
		(mid 347.841437 -219.754561)
		(end 347.564964 -219.82176)
		(width 0.0889)
		(layer "In4.Cu")
		(net "H_CPU0_CATERR_LVC1_R_N")
	)
	(arc
		(start 336.829146 -218.197684)
		(mid 336.698232 -218.061324)
		(end 336.650584 -217.878406)
		(width 0.0889)
		(layer "In4.Cu")
		(net "H_CPU0_CATERR_LVC1_R_N")
	)
	(arc
		(start 341.99195 -219.007944)
		(mid 341.715475 -218.940624)
		(end 341.441278 -219.01658)
		(width 0.0889)
		(layer "In4.Cu")
		(net "H_CPU0_CATERR_LVC1_R_N")
	)
	(arc
		(start 345.75115 -219.007944)
		(mid 345.474675 -218.940624)
		(end 345.200478 -219.01658)
		(width 0.0889)
		(layer "In4.Cu")
		(net "H_CPU0_CATERR_LVC1_R_N")
	)
	(arc
		(start 336.650584 -217.864182)
		(mid 336.571365 -217.589497)
		(end 336.367882 -217.388694)
		(width 0.0889)
		(layer "In4.Cu")
		(net "H_CPU0_CATERR_LVC1_R_N")
	)
	(arc
		(start 352.814636 -223.085914)
		(mid 352.531934 -223.010172)
		(end 352.249232 -223.085914)
		(width 0.0889)
		(layer "In4.Cu")
		(net "H_CPU0_CATERR_LVC1_R_N")
	)
	(arc
		(start 343.87155 -219.007944)
		(mid 343.595075 -218.940624)
		(end 343.320878 -219.01658)
		(width 0.0889)
		(layer "In4.Cu")
		(net "H_CPU0_CATERR_LVC1_R_N")
	)
	(arc
		(start 349.046546 -221.453202)
		(mid 348.915632 -221.316842)
		(end 348.867984 -221.133924)
		(width 0.0889)
		(layer "In4.Cu")
		(net "H_CPU0_CATERR_LVC1_R_N")
	)
	(arc
		(start 342.381078 -219.01658)
		(mid 342.19388 -219.066723)
		(end 342.006682 -219.01658)
		(width 0.0889)
		(layer "In4.Cu")
		(net "H_CPU0_CATERR_LVC1_R_N")
	)
	(arc
		(start 356.564946 -224.70872)
		(mid 356.434032 -224.57236)
		(end 356.386384 -224.389442)
		(width 0.0889)
		(layer "In4.Cu")
		(net "H_CPU0_CATERR_LVC1_R_N")
	)
	(arc
		(start 355.634036 -223.085914)
		(mid 355.359807 -223.009989)
		(end 355.083364 -223.077278)
		(width 0.0889)
		(layer "In4.Cu")
		(net "H_CPU0_CATERR_LVC1_R_N")
	)
	(arc
		(start 336.18043 -217.05443)
		(mid 336.102319 -216.777481)
		(end 335.897982 -216.574878)
		(width 0.0889)
		(layer "In4.Cu")
		(net "H_CPU0_CATERR_LVC1_R_N")
	)
	(arc
		(start 345.200478 -219.01658)
		(mid 345.01328 -219.066723)
		(end 344.826082 -219.01658)
		(width 0.0889)
		(layer "In4.Cu")
		(net "H_CPU0_CATERR_LVC1_R_N")
	)
	(arc
		(start 338.621878 -219.01658)
		(mid 338.43468 -219.066723)
		(end 338.247482 -219.01658)
		(width 0.0889)
		(layer "In4.Cu")
		(net "H_CPU0_CATERR_LVC1_R_N")
	)
	(arc
		(start 357.504746 -227.964238)
		(mid 357.326149 -227.64496)
		(end 357.504746 -227.325682)
		(width 0.0889)
		(layer "In4.Cu")
		(net "H_CPU0_CATERR_LVC1_R_N")
	)
	(arc
		(start 357.504746 -226.336606)
		(mid 357.373832 -226.200246)
		(end 357.326184 -226.017328)
		(width 0.0889)
		(layer "In4.Cu")
		(net "H_CPU0_CATERR_LVC1_R_N")
	)
	(arc
		(start 346.140278 -219.01658)
		(mid 345.95308 -219.066723)
		(end 345.765882 -219.01658)
		(width 0.0889)
		(layer "In4.Cu")
		(net "H_CPU0_CATERR_LVC1_R_N")
	)
	(arc
		(start 357.796084 -231.706928)
		(mid 357.718455 -231.428515)
		(end 357.513382 -231.224836)
		(width 0.0889)
		(layer "In4.Cu")
		(net "H_CPU0_CATERR_LVC1_R_N")
	)
	(arc
		(start 335.66481 -216.370408)
		(mid 335.587891 -216.269087)
		(end 335.541366 -216.150698)
		(width 0.0889)
		(layer "In4.Cu")
		(net "H_CPU0_CATERR_LVC1_R_N")
	)
	(arc
		(start 335.541366 -216.150698)
		(mid 335.494958 -216.032323)
		(end 335.418176 -215.930988)
		(width 0.0889)
		(layer "In4.Cu")
		(net "H_CPU0_CATERR_LVC1_R_N")
	)
	(arc
		(start 337.120484 -218.682316)
		(mid 337.042373 -218.405367)
		(end 336.838036 -218.202764)
		(width 0.0889)
		(layer "In4.Cu")
		(net "H_CPU0_CATERR_LVC1_R_N")
	)
	(arc
		(start 340.11235 -219.007944)
		(mid 339.835875 -218.940624)
		(end 339.561678 -219.01658)
		(width 0.0889)
		(layer "In4.Cu")
		(net "H_CPU0_CATERR_LVC1_R_N")
	)
	(arc
		(start 357.513636 -228.948488)
		(mid 357.716459 -228.748257)
		(end 357.79583 -228.474524)
		(width 0.0889)
		(layer "In4.Cu")
		(net "H_CPU0_CATERR_LVC1_R_N")
	)
	(arc
		(start 357.034592 -225.522536)
		(mid 356.903678 -225.386176)
		(end 356.85603 -225.203258)
		(width 0.0889)
		(layer "In4.Cu")
		(net "H_CPU0_CATERR_LVC1_R_N")
	)
	(arc
		(start 348.867984 -221.115382)
		(mid 348.787822 -220.843193)
		(end 348.585536 -220.644212)
		(width 0.0889)
		(layer "In4.Cu")
		(net "H_CPU0_CATERR_LVC1_R_N")
	)
	(arc
		(start 353.754436 -223.085914)
		(mid 353.480207 -223.009989)
		(end 353.203764 -223.077278)
		(width 0.0889)
		(layer "In4.Cu")
		(net "H_CPU0_CATERR_LVC1_R_N")
	)
	(arc
		(start 356.386384 -224.379536)
		(mid 356.308273 -224.102587)
		(end 356.103936 -223.899984)
		(width 0.0889)
		(layer "In4.Cu")
		(net "H_CPU0_CATERR_LVC1_R_N")
	)
	(arc
		(start 339.561678 -219.01658)
		(mid 339.37448 -219.066723)
		(end 339.187282 -219.01658)
		(width 0.0889)
		(layer "In4.Cu")
		(net "H_CPU0_CATERR_LVC1_R_N")
	)
	(arc
		(start 341.441278 -219.01658)
		(mid 341.25408 -219.066723)
		(end 341.066882 -219.01658)
		(width 0.0889)
		(layer "In4.Cu")
		(net "H_CPU0_CATERR_LVC1_R_N")
	)
	(arc
		(start 354.324158 -223.09201)
		(mid 354.106348 -223.199226)
		(end 353.868228 -223.1517)
		(width 0.0889)
		(layer "In4.Cu")
		(net "H_CPU0_CATERR_LVC1_R_N")
	)
	(arc
		(start 357.519732 -227.317046)
		(mid 357.796058 -226.831144)
		(end 357.519732 -226.345242)
		(width 0.0889)
		(layer "In4.Cu")
		(net "H_CPU0_CATERR_LVC1_R_N")
	)
	(arc
		(start 351.309432 -223.085914)
		(mid 351.122234 -223.136057)
		(end 350.935036 -223.085914)
		(width 0.0889)
		(layer "In4.Cu")
		(net "H_CPU0_CATERR_LVC1_R_N")
	)
	(arc
		(start 346.69095 -219.007944)
		(mid 346.414475 -218.940624)
		(end 346.140278 -219.01658)
		(width 0.0889)
		(layer "In4.Cu")
		(net "H_CPU0_CATERR_LVC1_R_N")
	)
	(arc
		(start 353.189032 -223.085914)
		(mid 353.001834 -223.136057)
		(end 352.814636 -223.085914)
		(width 0.0889)
		(layer "In4.Cu")
		(net "H_CPU0_CATERR_LVC1_R_N")
	)
	(arc
		(start 339.17255 -219.007944)
		(mid 338.896075 -218.940624)
		(end 338.621878 -219.01658)
		(width 0.0889)
		(layer "In4.Cu")
		(net "H_CPU0_CATERR_LVC1_R_N")
	)
	(arc
		(start 357.519732 -232.20045)
		(mid 357.722145 -231.994037)
		(end 357.796084 -231.714548)
		(width 0.0889)
		(layer "In4.Cu")
		(net "H_CPU0_CATERR_LVC1_R_N")
	)
	(arc
		(start 357.326184 -229.272846)
		(mid 357.373863 -229.089946)
		(end 357.504746 -228.953568)
		(width 0.0889)
		(layer "In4.Cu")
		(net "H_CPU0_CATERR_LVC1_R_N")
	)
	(arc
		(start 350.369632 -223.085914)
		(mid 350.182434 -223.136057)
		(end 349.995236 -223.085914)
		(width 0.0889)
		(layer "In4.Cu")
		(net "H_CPU0_CATERR_LVC1_R_N")
	)
	(arc
		(start 357.664258 -230.35641)
		(mid 357.751056 -230.14686)
		(end 357.664258 -229.93731)
		(width 0.0889)
		(layer "In4.Cu")
		(net "H_CPU0_CATERR_LVC1_R_N")
	)
	(arc
		(start 355.916484 -223.561402)
		(mid 355.837343 -223.286779)
		(end 355.634036 -223.085914)
		(width 0.0889)
		(layer "In4.Cu")
		(net "H_CPU0_CATERR_LVC1_R_N")
	)
	(arc
		(start 357.466138 -232.82021)
		(mid 357.362993 -232.690185)
		(end 357.326184 -232.528364)
		(width 0.0889)
		(layer "In4.Cu")
		(net "H_CPU0_CATERR_LVC1_R_N")
	)
	(arc
		(start 351.874836 -223.085914)
		(mid 351.600607 -223.009989)
		(end 351.324164 -223.077278)
		(width 0.0889)
		(layer "In4.Cu")
		(net "H_CPU0_CATERR_LVC1_R_N")
	)
	(arc
		(start 352.249232 -223.085914)
		(mid 352.062034 -223.136057)
		(end 351.874836 -223.085914)
		(width 0.0889)
		(layer "In4.Cu")
		(net "H_CPU0_CATERR_LVC1_R_N")
	)
	(arc
		(start 346.988384 -219.506038)
		(mid 346.914393 -219.226472)
		(end 346.711778 -219.020136)
		(width 0.0889)
		(layer "In4.Cu")
		(net "H_CPU0_CATERR_LVC1_R_N")
	)
	(arc
		(start 342.93175 -219.007944)
		(mid 342.655275 -218.940624)
		(end 342.381078 -219.01658)
		(width 0.0889)
		(layer "In4.Cu")
		(net "H_CPU0_CATERR_LVC1_R_N")
	)
	(segment
		(start 357.230934 -232.250488)
		(end 357.23068 -232.250234)
		(width 0.12954)
		(layer "F.Cu")
		(net "H_CPU0_BMCINIT_LVC1")
	)
	(segment
		(start 357.23068 -232.250234)
		(end 357.23068 -231.714548)
		(width 0.12954)
		(layer "F.Cu")
		(net "H_CPU0_BMCINIT_LVC1")
	)
	(via
		(at 357.23068 -231.714548)
		(size 0.4572)
		(drill 0.2032)
		(layers "F.Cu" "B.Cu")
		(net "H_CPU0_BMCINIT_LVC1")
	)
	(via
		(at 331.499718 -202.46975)
		(size 0.508)
		(drill 0.254)
		(layers "F.Cu" "B.Cu")
		(net "H_CPU0_BMCINIT_LVC1")
	)
	(segment
		(start 329.135232 -199.628252)
		(end 328.90333 -199.068436)
		(width 0.12954)
		(layer "B.Cu")
		(net "H_CPU0_BMCINIT_LVC1")
	)
	(segment
		(start 330.190348 -201.16038)
		(end 330.190348 -200.683368)
		(width 0.12954)
		(layer "B.Cu")
		(net "H_CPU0_BMCINIT_LVC1")
	)
	(segment
		(start 328.967338 -188.937646)
		(end 328.967338 -188.62167)
		(width 0.12954)
		(layer "B.Cu")
		(net "H_CPU0_BMCINIT_LVC1")
	)
	(segment
		(start 328.433938 -188.08827)
		(end 328.433938 -185.7629)
		(width 0.12954)
		(layer "B.Cu")
		(net "H_CPU0_BMCINIT_LVC1")
	)
	(segment
		(start 331.499718 -202.46975)
		(end 330.190348 -201.16038)
		(width 0.12954)
		(layer "B.Cu")
		(net "H_CPU0_BMCINIT_LVC1")
	)
	(segment
		(start 328.433938 -185.7629)
		(end 328.169778 -185.49874)
		(width 0.12954)
		(layer "B.Cu")
		(net "H_CPU0_BMCINIT_LVC1")
	)
	(segment
		(start 329.421998 -189.392306)
		(end 328.967338 -188.937646)
		(width 0.12954)
		(layer "B.Cu")
		(net "H_CPU0_BMCINIT_LVC1")
	)
	(segment
		(start 329.421998 -196.016372)
		(end 329.421998 -189.392306)
		(width 0.12954)
		(layer "B.Cu")
		(net "H_CPU0_BMCINIT_LVC1")
	)
	(segment
		(start 328.90333 -196.53504)
		(end 329.421998 -196.016372)
		(width 0.12954)
		(layer "B.Cu")
		(net "H_CPU0_BMCINIT_LVC1")
	)
	(segment
		(start 328.967338 -188.62167)
		(end 328.433938 -188.08827)
		(width 0.12954)
		(layer "B.Cu")
		(net "H_CPU0_BMCINIT_LVC1")
	)
	(segment
		(start 330.190348 -200.683368)
		(end 329.135232 -199.628252)
		(width 0.12954)
		(layer "B.Cu")
		(net "H_CPU0_BMCINIT_LVC1")
	)
	(segment
		(start 328.90333 -199.068436)
		(end 328.90333 -196.53504)
		(width 0.12954)
		(layer "B.Cu")
		(net "H_CPU0_BMCINIT_LVC1")
	)
	(segment
		(start 348.585536 -223.900238)
		(end 348.57563 -223.894396)
		(width 0.0889)
		(layer "In4.Cu")
		(net "H_CPU0_BMCINIT_LVC1")
	)
	(segment
		(start 346.714064 -222.277178)
		(end 346.705682 -222.272352)
		(width 0.0889)
		(layer "In4.Cu")
		(net "H_CPU0_BMCINIT_LVC1")
	)
	(segment
		(start 338.166964 -219.82176)
		(end 338.152232 -219.830396)
		(width 0.0889)
		(layer "In4.Cu")
		(net "H_CPU0_BMCINIT_LVC1")
	)
	(segment
		(start 345.10853 -221.133924)
		(end 345.10853 -221.11843)
		(width 0.0889)
		(layer "In4.Cu")
		(net "H_CPU0_BMCINIT_LVC1")
	)
	(segment
		(start 356.103682 -230.41102)
		(end 356.094792 -230.40594)
		(width 0.0889)
		(layer "In4.Cu")
		(net "H_CPU0_BMCINIT_LVC1")
	)
	(segment
		(start 356.573836 -231.224836)
		(end 356.564946 -231.219756)
		(width 0.0889)
		(layer "In4.Cu")
		(net "H_CPU0_BMCINIT_LVC1")
	)
	(segment
		(start 345.681046 -221.45244)
		(end 345.670632 -221.458536)
		(width 0.0889)
		(layer "In4.Cu")
		(net "H_CPU0_BMCINIT_LVC1")
	)
	(segment
		(start 355.163882 -225.527616)
		(end 355.14915 -225.51898)
		(width 0.0889)
		(layer "In4.Cu")
		(net "H_CPU0_BMCINIT_LVC1")
	)
	(segment
		(start 336.085434 -219.880434)
		(end 335.929986 -219.880434)
		(width 0.0889)
		(layer "In4.Cu")
		(net "H_CPU0_BMCINIT_LVC1")
	)
	(segment
		(start 350.464882 -225.527616)
		(end 350.455992 -225.522536)
		(width 0.0889)
		(layer "In4.Cu")
		(net "H_CPU0_BMCINIT_LVC1")
	)
	(segment
		(start 346.705682 -222.272352)
		(end 346.699078 -222.268542)
		(width 0.0889)
		(layer "In4.Cu")
		(net "H_CPU0_BMCINIT_LVC1")
	)
	(segment
		(start 351.404682 -225.527616)
		(end 351.38995 -225.51898)
		(width 0.0889)
		(layer "In4.Cu")
		(net "H_CPU0_BMCINIT_LVC1")
	)
	(segment
		(start 333.770478 -217.97899)
		(end 333.770478 -217.72499)
		(width 0.0889)
		(layer "In4.Cu")
		(net "H_CPU0_BMCINIT_LVC1")
	)
	(segment
		(start 347.648276 -222.27413)
		(end 347.645482 -222.272352)
		(width 0.0889)
		(layer "In4.Cu")
		(net "H_CPU0_BMCINIT_LVC1")
	)
	(segment
		(start 344.826082 -220.644466)
		(end 344.820494 -220.641418)
		(width 0.0889)
		(layer "In4.Cu")
		(net "H_CPU0_BMCINIT_LVC1")
	)
	(segment
		(start 346.699078 -222.268542)
		(end 346.695776 -222.26651)
		(width 0.0889)
		(layer "In4.Cu")
		(net "H_CPU0_BMCINIT_LVC1")
	)
	(segment
		(start 355.634036 -227.320602)
		(end 355.640132 -227.317046)
		(width 0.0889)
		(layer "In4.Cu")
		(net "H_CPU0_BMCINIT_LVC1")
	)
	(segment
		(start 332.08087 -214.274654)
		(end 331.499718 -211.352892)
		(width 0.127)
		(layer "In4.Cu")
		(net "H_CPU0_BMCINIT_LVC1")
	)
	(segment
		(start 341.926164 -219.82176)
		(end 341.911432 -219.830396)
		(width 0.0889)
		(layer "In4.Cu")
		(net "H_CPU0_BMCINIT_LVC1")
	)
	(segment
		(start 355.446584 -227.651564)
		(end 355.446584 -227.64496)
		(width 0.0889)
		(layer "In4.Cu")
		(net "H_CPU0_BMCINIT_LVC1")
	)
	(segment
		(start 355.634036 -226.341686)
		(end 355.625146 -226.336606)
		(width 0.0889)
		(layer "In4.Cu")
		(net "H_CPU0_BMCINIT_LVC1")
	)
	(segment
		(start 355.446584 -226.017328)
		(end 355.446584 -226.003104)
		(width 0.0889)
		(layer "In4.Cu")
		(net "H_CPU0_BMCINIT_LVC1")
	)
	(segment
		(start 355.62667 -228.036882)
		(end 355.591618 -228.00183)
		(width 0.0889)
		(layer "In4.Cu")
		(net "H_CPU0_BMCINIT_LVC1")
	)
	(segment
		(start 335.929986 -219.880434)
		(end 334.457802 -218.40825)
		(width 0.0889)
		(layer "In4.Cu")
		(net "H_CPU0_BMCINIT_LVC1")
	)
	(segment
		(start 340.046564 -219.82176)
		(end 340.031832 -219.830396)
		(width 0.0889)
		(layer "In4.Cu")
		(net "H_CPU0_BMCINIT_LVC1")
	)
	(segment
		(start 356.115874 -230.418132)
		(end 356.103682 -230.41102)
		(width 0.0889)
		(layer "In4.Cu")
		(net "H_CPU0_BMCINIT_LVC1")
	)
	(segment
		(start 344.367104 -219.837)
		(end 344.356182 -219.83065)
		(width 0.0889)
		(layer "In4.Cu")
		(net "H_CPU0_BMCINIT_LVC1")
	)
	(segment
		(start 352.344482 -225.527616)
		(end 352.32975 -225.51898)
		(width 0.0889)
		(layer "In4.Cu")
		(net "H_CPU0_BMCINIT_LVC1")
	)
	(segment
		(start 353.284282 -225.527616)
		(end 353.26955 -225.51898)
		(width 0.0889)
		(layer "In4.Cu")
		(net "H_CPU0_BMCINIT_LVC1")
	)
	(segment
		(start 331.499718 -211.352892)
		(end 331.499718 -202.46975)
		(width 0.127)
		(layer "In4.Cu")
		(net "H_CPU0_BMCINIT_LVC1")
	)
	(segment
		(start 347.645482 -222.272352)
		(end 347.641164 -222.269558)
		(width 0.0889)
		(layer "In4.Cu")
		(net "H_CPU0_BMCINIT_LVC1")
	)
	(segment
		(start 347.641164 -222.269558)
		(end 347.635068 -222.266256)
		(width 0.0889)
		(layer "In4.Cu")
		(net "H_CPU0_BMCINIT_LVC1")
	)
	(segment
		(start 349.055436 -224.7138)
		(end 349.046546 -224.70872)
		(width 0.0889)
		(layer "In4.Cu")
		(net "H_CPU0_BMCINIT_LVC1")
	)
	(segment
		(start 355.640132 -226.345242)
		(end 355.634036 -226.341686)
		(width 0.0889)
		(layer "In4.Cu")
		(net "H_CPU0_BMCINIT_LVC1")
	)
	(segment
		(start 355.796596 -228.423978)
		(end 355.651308 -228.073712)
		(width 0.0889)
		(layer "In4.Cu")
		(net "H_CPU0_BMCINIT_LVC1")
	)
	(segment
		(start 350.27743 -225.203258)
		(end 350.27743 -225.187764)
		(width 0.0889)
		(layer "In4.Cu")
		(net "H_CPU0_BMCINIT_LVC1")
	)
	(segment
		(start 354.224082 -225.527616)
		(end 354.20935 -225.51898)
		(width 0.0889)
		(layer "In4.Cu")
		(net "H_CPU0_BMCINIT_LVC1")
	)
	(segment
		(start 355.625146 -227.325682)
		(end 355.634036 -227.320602)
		(width 0.0889)
		(layer "In4.Cu")
		(net "H_CPU0_BMCINIT_LVC1")
	)
	(segment
		(start 345.670632 -221.458536)
		(end 345.66225 -221.463362)
		(width 0.0889)
		(layer "In4.Cu")
		(net "H_CPU0_BMCINIT_LVC1")
	)
	(segment
		(start 344.356182 -219.83065)
		(end 344.356436 -219.830396)
		(width 0.0889)
		(layer "In4.Cu")
		(net "H_CPU0_BMCINIT_LVC1")
	)
	(segment
		(start 355.634036 -229.597204)
		(end 355.625146 -229.592124)
		(width 0.0889)
		(layer "In4.Cu")
		(net "H_CPU0_BMCINIT_LVC1")
	)
	(segment
		(start 348.39783 -223.575626)
		(end 348.39783 -223.56572)
		(width 0.0889)
		(layer "In4.Cu")
		(net "H_CPU0_BMCINIT_LVC1")
	)
	(segment
		(start 348.115382 -223.086168)
		(end 348.109794 -223.08312)
		(width 0.0889)
		(layer "In4.Cu")
		(net "H_CPU0_BMCINIT_LVC1")
	)
	(segment
		(start 346.517976 -221.94774)
		(end 346.517976 -221.936056)
		(width 0.0889)
		(layer "In4.Cu")
		(net "H_CPU0_BMCINIT_LVC1")
	)
	(segment
		(start 348.867984 -224.389442)
		(end 348.867984 -224.379536)
		(width 0.0889)
		(layer "In4.Cu")
		(net "H_CPU0_BMCINIT_LVC1")
	)
	(segment
		(start 348.585536 -223.899984)
		(end 348.585536 -223.900238)
		(width 0.0889)
		(layer "In4.Cu")
		(net "H_CPU0_BMCINIT_LVC1")
	)
	(segment
		(start 355.91623 -230.086662)
		(end 355.91623 -230.071168)
		(width 0.0889)
		(layer "In4.Cu")
		(net "H_CPU0_BMCINIT_LVC1")
	)
	(segment
		(start 345.295982 -221.458536)
		(end 345.290394 -221.455488)
		(width 0.0889)
		(layer "In4.Cu")
		(net "H_CPU0_BMCINIT_LVC1")
	)
	(segment
		(start 333.325978 -217.28049)
		(end 332.08087 -214.274654)
		(width 0.127)
		(layer "In4.Cu")
		(net "H_CPU0_BMCINIT_LVC1")
	)
	(segment
		(start 333.770478 -217.72499)
		(end 333.325978 -217.28049)
		(width 0.0889)
		(layer "In4.Cu")
		(net "H_CPU0_BMCINIT_LVC1")
	)
	(segment
		(start 343.805764 -219.82176)
		(end 343.791032 -219.830396)
		(width 0.0889)
		(layer "In4.Cu")
		(net "H_CPU0_BMCINIT_LVC1")
	)
	(segment
		(start 334.457802 -218.40825)
		(end 334.199738 -218.40825)
		(width 0.0889)
		(layer "In4.Cu")
		(net "H_CPU0_BMCINIT_LVC1")
	)
	(segment
		(start 349.444564 -224.705164)
		(end 349.429832 -224.7138)
		(width 0.0889)
		(layer "In4.Cu")
		(net "H_CPU0_BMCINIT_LVC1")
	)
	(segment
		(start 334.199738 -218.40825)
		(end 333.770478 -217.97899)
		(width 0.0889)
		(layer "In4.Cu")
		(net "H_CPU0_BMCINIT_LVC1")
	)
	(arc
		(start 350.839278 -225.527616)
		(mid 350.65208 -225.577759)
		(end 350.464882 -225.527616)
		(width 0.0889)
		(layer "In4.Cu")
		(net "H_CPU0_BMCINIT_LVC1")
	)
	(arc
		(start 355.651308 -228.073712)
		(mid 355.640796 -228.05409)
		(end 355.62667 -228.036882)
		(width 0.0889)
		(layer "In4.Cu")
		(net "H_CPU0_BMCINIT_LVC1")
	)
	(arc
		(start 354.20935 -225.51898)
		(mid 353.932909 -225.451814)
		(end 353.658678 -225.527616)
		(width 0.0889)
		(layer "In4.Cu")
		(net "H_CPU0_BMCINIT_LVC1")
	)
	(arc
		(start 336.272632 -219.830396)
		(mid 336.182325 -219.867725)
		(end 336.085434 -219.880434)
		(width 0.0889)
		(layer "In4.Cu")
		(net "H_CPU0_BMCINIT_LVC1")
	)
	(arc
		(start 355.446584 -226.003104)
		(mid 355.367365 -225.728419)
		(end 355.163882 -225.527616)
		(width 0.0889)
		(layer "In4.Cu")
		(net "H_CPU0_BMCINIT_LVC1")
	)
	(arc
		(start 345.290394 -221.455488)
		(mid 345.157124 -221.318646)
		(end 345.10853 -221.133924)
		(width 0.0889)
		(layer "In4.Cu")
		(net "H_CPU0_BMCINIT_LVC1")
	)
	(arc
		(start 352.718878 -225.527616)
		(mid 352.53168 -225.577759)
		(end 352.344482 -225.527616)
		(width 0.0889)
		(layer "In4.Cu")
		(net "H_CPU0_BMCINIT_LVC1")
	)
	(arc
		(start 356.564946 -231.219756)
		(mid 356.434032 -231.083396)
		(end 356.386384 -230.900478)
		(width 0.0889)
		(layer "In4.Cu")
		(net "H_CPU0_BMCINIT_LVC1")
	)
	(arc
		(start 342.851232 -219.830396)
		(mid 342.664034 -219.880539)
		(end 342.476836 -219.830396)
		(width 0.0889)
		(layer "In4.Cu")
		(net "H_CPU0_BMCINIT_LVC1")
	)
	(arc
		(start 340.971632 -219.830396)
		(mid 340.784434 -219.880539)
		(end 340.597236 -219.830396)
		(width 0.0889)
		(layer "In4.Cu")
		(net "H_CPU0_BMCINIT_LVC1")
	)
	(arc
		(start 355.640132 -227.317046)
		(mid 355.916458 -226.831144)
		(end 355.640132 -226.345242)
		(width 0.0889)
		(layer "In4.Cu")
		(net "H_CPU0_BMCINIT_LVC1")
	)
	(arc
		(start 337.777836 -219.830396)
		(mid 337.495134 -219.75462)
		(end 337.212432 -219.830396)
		(width 0.0889)
		(layer "In4.Cu")
		(net "H_CPU0_BMCINIT_LVC1")
	)
	(arc
		(start 340.031832 -219.830396)
		(mid 339.844634 -219.880539)
		(end 339.657436 -219.830396)
		(width 0.0889)
		(layer "In4.Cu")
		(net "H_CPU0_BMCINIT_LVC1")
	)
	(arc
		(start 348.109794 -223.08312)
		(mid 347.976524 -222.946278)
		(end 347.92793 -222.761556)
		(width 0.0889)
		(layer "In4.Cu")
		(net "H_CPU0_BMCINIT_LVC1")
	)
	(arc
		(start 351.38995 -225.51898)
		(mid 351.113509 -225.451814)
		(end 350.839278 -225.527616)
		(width 0.0889)
		(layer "In4.Cu")
		(net "H_CPU0_BMCINIT_LVC1")
	)
	(arc
		(start 343.791032 -219.830396)
		(mid 343.603834 -219.880539)
		(end 343.416636 -219.830396)
		(width 0.0889)
		(layer "In4.Cu")
		(net "H_CPU0_BMCINIT_LVC1")
	)
	(arc
		(start 352.32975 -225.51898)
		(mid 352.053309 -225.451814)
		(end 351.779078 -225.527616)
		(width 0.0889)
		(layer "In4.Cu")
		(net "H_CPU0_BMCINIT_LVC1")
	)
	(arc
		(start 345.10853 -221.11843)
		(mid 345.029081 -220.844634)
		(end 344.826082 -220.644466)
		(width 0.0889)
		(layer "In4.Cu")
		(net "H_CPU0_BMCINIT_LVC1")
	)
	(arc
		(start 356.386384 -230.900478)
		(mid 356.314149 -230.623954)
		(end 356.115874 -230.418132)
		(width 0.0889)
		(layer "In4.Cu")
		(net "H_CPU0_BMCINIT_LVC1")
	)
	(arc
		(start 355.625146 -228.953568)
		(mid 355.808622 -228.720396)
		(end 355.796596 -228.423978)
		(width 0.0889)
		(layer "In4.Cu")
		(net "H_CPU0_BMCINIT_LVC1")
	)
	(arc
		(start 341.537036 -219.830396)
		(mid 341.254334 -219.75462)
		(end 340.971632 -219.830396)
		(width 0.0889)
		(layer "In4.Cu")
		(net "H_CPU0_BMCINIT_LVC1")
	)
	(arc
		(start 355.591618 -228.00183)
		(mid 355.484239 -227.841127)
		(end 355.446584 -227.651564)
		(width 0.0889)
		(layer "In4.Cu")
		(net "H_CPU0_BMCINIT_LVC1")
	)
	(arc
		(start 339.657436 -219.830396)
		(mid 339.374734 -219.75462)
		(end 339.092032 -219.830396)
		(width 0.0889)
		(layer "In4.Cu")
		(net "H_CPU0_BMCINIT_LVC1")
	)
	(arc
		(start 355.91623 -230.071168)
		(mid 355.83686 -229.797434)
		(end 355.634036 -229.597204)
		(width 0.0889)
		(layer "In4.Cu")
		(net "H_CPU0_BMCINIT_LVC1")
	)
	(arc
		(start 343.416636 -219.830396)
		(mid 343.133934 -219.75462)
		(end 342.851232 -219.830396)
		(width 0.0889)
		(layer "In4.Cu")
		(net "H_CPU0_BMCINIT_LVC1")
	)
	(arc
		(start 340.597236 -219.830396)
		(mid 340.323037 -219.754561)
		(end 340.046564 -219.82176)
		(width 0.0889)
		(layer "In4.Cu")
		(net "H_CPU0_BMCINIT_LVC1")
	)
	(arc
		(start 344.63863 -220.319854)
		(mid 344.566098 -220.042866)
		(end 344.367104 -219.837)
		(width 0.0889)
		(layer "In4.Cu")
		(net "H_CPU0_BMCINIT_LVC1")
	)
	(arc
		(start 351.779078 -225.527616)
		(mid 351.59188 -225.577759)
		(end 351.404682 -225.527616)
		(width 0.0889)
		(layer "In4.Cu")
		(net "H_CPU0_BMCINIT_LVC1")
	)
	(arc
		(start 347.92793 -222.761556)
		(mid 347.853054 -222.480576)
		(end 347.648276 -222.27413)
		(width 0.0889)
		(layer "In4.Cu")
		(net "H_CPU0_BMCINIT_LVC1")
	)
	(arc
		(start 354.598478 -225.527616)
		(mid 354.41128 -225.577759)
		(end 354.224082 -225.527616)
		(width 0.0889)
		(layer "In4.Cu")
		(net "H_CPU0_BMCINIT_LVC1")
	)
	(arc
		(start 355.446584 -227.64496)
		(mid 355.494263 -227.46206)
		(end 355.625146 -227.325682)
		(width 0.0889)
		(layer "In4.Cu")
		(net "H_CPU0_BMCINIT_LVC1")
	)
	(arc
		(start 344.820494 -220.641418)
		(mid 344.687224 -220.504576)
		(end 344.63863 -220.319854)
		(width 0.0889)
		(layer "In4.Cu")
		(net "H_CPU0_BMCINIT_LVC1")
	)
	(arc
		(start 357.23068 -231.714548)
		(mid 356.917156 -231.449708)
		(end 356.573836 -231.224836)
		(width 0.0889)
		(layer "In4.Cu")
		(net "H_CPU0_BMCINIT_LVC1")
	)
	(arc
		(start 356.094792 -230.40594)
		(mid 355.963878 -230.26958)
		(end 355.91623 -230.086662)
		(width 0.0889)
		(layer "In4.Cu")
		(net "H_CPU0_BMCINIT_LVC1")
	)
	(arc
		(start 353.658678 -225.527616)
		(mid 353.47148 -225.577759)
		(end 353.284282 -225.527616)
		(width 0.0889)
		(layer "In4.Cu")
		(net "H_CPU0_BMCINIT_LVC1")
	)
	(arc
		(start 341.911432 -219.830396)
		(mid 341.724234 -219.880539)
		(end 341.537036 -219.830396)
		(width 0.0889)
		(layer "In4.Cu")
		(net "H_CPU0_BMCINIT_LVC1")
	)
	(arc
		(start 353.26955 -225.51898)
		(mid 352.993109 -225.451814)
		(end 352.718878 -225.527616)
		(width 0.0889)
		(layer "In4.Cu")
		(net "H_CPU0_BMCINIT_LVC1")
	)
	(arc
		(start 346.695776 -222.26651)
		(mid 346.56543 -222.130242)
		(end 346.517976 -221.94774)
		(width 0.0889)
		(layer "In4.Cu")
		(net "H_CPU0_BMCINIT_LVC1")
	)
	(arc
		(start 338.152232 -219.830396)
		(mid 337.965034 -219.880539)
		(end 337.777836 -219.830396)
		(width 0.0889)
		(layer "In4.Cu")
		(net "H_CPU0_BMCINIT_LVC1")
	)
	(arc
		(start 345.66225 -221.463362)
		(mid 345.478488 -221.508731)
		(end 345.295982 -221.458536)
		(width 0.0889)
		(layer "In4.Cu")
		(net "H_CPU0_BMCINIT_LVC1")
	)
	(arc
		(start 336.838036 -219.830396)
		(mid 336.555334 -219.75462)
		(end 336.272632 -219.830396)
		(width 0.0889)
		(layer "In4.Cu")
		(net "H_CPU0_BMCINIT_LVC1")
	)
	(arc
		(start 349.429832 -224.7138)
		(mid 349.242634 -224.763943)
		(end 349.055436 -224.7138)
		(width 0.0889)
		(layer "In4.Cu")
		(net "H_CPU0_BMCINIT_LVC1")
	)
	(arc
		(start 347.635068 -222.266256)
		(mid 347.35689 -222.196501)
		(end 347.080332 -222.272352)
		(width 0.0889)
		(layer "In4.Cu")
		(net "H_CPU0_BMCINIT_LVC1")
	)
	(arc
		(start 348.39783 -223.56572)
		(mid 348.319719 -223.288771)
		(end 348.115382 -223.086168)
		(width 0.0889)
		(layer "In4.Cu")
		(net "H_CPU0_BMCINIT_LVC1")
	)
	(arc
		(start 349.046546 -224.70872)
		(mid 348.915632 -224.57236)
		(end 348.867984 -224.389442)
		(width 0.0889)
		(layer "In4.Cu")
		(net "H_CPU0_BMCINIT_LVC1")
	)
	(arc
		(start 349.995236 -224.7138)
		(mid 349.721037 -224.637965)
		(end 349.444564 -224.705164)
		(width 0.0889)
		(layer "In4.Cu")
		(net "H_CPU0_BMCINIT_LVC1")
	)
	(arc
		(start 350.455992 -225.522536)
		(mid 350.325078 -225.386176)
		(end 350.27743 -225.203258)
		(width 0.0889)
		(layer "In4.Cu")
		(net "H_CPU0_BMCINIT_LVC1")
	)
	(arc
		(start 350.27743 -225.187764)
		(mid 350.19806 -224.91403)
		(end 349.995236 -224.7138)
		(width 0.0889)
		(layer "In4.Cu")
		(net "H_CPU0_BMCINIT_LVC1")
	)
	(arc
		(start 347.080332 -222.272352)
		(mid 346.897827 -222.322556)
		(end 346.714064 -222.277178)
		(width 0.0889)
		(layer "In4.Cu")
		(net "H_CPU0_BMCINIT_LVC1")
	)
	(arc
		(start 348.57563 -223.894396)
		(mid 348.445284 -223.758128)
		(end 348.39783 -223.575626)
		(width 0.0889)
		(layer "In4.Cu")
		(net "H_CPU0_BMCINIT_LVC1")
	)
	(arc
		(start 346.517976 -221.936056)
		(mid 346.439509 -221.660284)
		(end 346.235782 -221.458536)
		(width 0.0889)
		(layer "In4.Cu")
		(net "H_CPU0_BMCINIT_LVC1")
	)
	(arc
		(start 337.212432 -219.830396)
		(mid 337.025234 -219.880539)
		(end 336.838036 -219.830396)
		(width 0.0889)
		(layer "In4.Cu")
		(net "H_CPU0_BMCINIT_LVC1")
	)
	(arc
		(start 344.356436 -219.830396)
		(mid 344.082237 -219.754561)
		(end 343.805764 -219.82176)
		(width 0.0889)
		(layer "In4.Cu")
		(net "H_CPU0_BMCINIT_LVC1")
	)
	(arc
		(start 355.625146 -229.592124)
		(mid 355.446549 -229.272846)
		(end 355.625146 -228.953568)
		(width 0.0889)
		(layer "In4.Cu")
		(net "H_CPU0_BMCINIT_LVC1")
	)
	(arc
		(start 355.625146 -226.336606)
		(mid 355.494232 -226.200246)
		(end 355.446584 -226.017328)
		(width 0.0889)
		(layer "In4.Cu")
		(net "H_CPU0_BMCINIT_LVC1")
	)
	(arc
		(start 338.717636 -219.830396)
		(mid 338.443437 -219.754561)
		(end 338.166964 -219.82176)
		(width 0.0889)
		(layer "In4.Cu")
		(net "H_CPU0_BMCINIT_LVC1")
	)
	(arc
		(start 348.867984 -224.379536)
		(mid 348.789873 -224.102587)
		(end 348.585536 -223.899984)
		(width 0.0889)
		(layer "In4.Cu")
		(net "H_CPU0_BMCINIT_LVC1")
	)
	(arc
		(start 339.092032 -219.830396)
		(mid 338.904834 -219.880539)
		(end 338.717636 -219.830396)
		(width 0.0889)
		(layer "In4.Cu")
		(net "H_CPU0_BMCINIT_LVC1")
	)
	(arc
		(start 355.14915 -225.51898)
		(mid 354.872709 -225.451814)
		(end 354.598478 -225.527616)
		(width 0.0889)
		(layer "In4.Cu")
		(net "H_CPU0_BMCINIT_LVC1")
	)
	(arc
		(start 346.235782 -221.458536)
		(mid 345.959223 -221.382759)
		(end 345.681046 -221.45244)
		(width 0.0889)
		(layer "In4.Cu")
		(net "H_CPU0_BMCINIT_LVC1")
	)
	(arc
		(start 342.476836 -219.830396)
		(mid 342.202637 -219.754561)
		(end 341.926164 -219.82176)
		(width 0.0889)
		(layer "In4.Cu")
		(net "H_CPU0_BMCINIT_LVC1")
	)
	(segment
		(start 133.54812 -121.07926)
		(end 133.3627 -120.89384)
		(width 0.12954)
		(layer "F.Cu")
		(net "HP_OCP_V3_2_EN")
	)
	(segment
		(start 132.314696 -120.600216)
		(end 132.314696 -119.425974)
		(width 0.12954)
		(layer "F.Cu")
		(net "HP_OCP_V3_2_EN")
	)
	(segment
		(start 137.808716 -121.536968)
		(end 134.78002 -121.536968)
		(width 0.12954)
		(layer "F.Cu")
		(net "HP_OCP_V3_2_EN")
	)
	(segment
		(start 133.54812 -121.492518)
		(end 133.54812 -121.07926)
		(width 0.12954)
		(layer "F.Cu")
		(net "HP_OCP_V3_2_EN")
	)
	(segment
		(start 133.59257 -121.536968)
		(end 134.78002 -121.536968)
		(width 0.12954)
		(layer "F.Cu")
		(net "HP_OCP_V3_2_EN")
	)
	(segment
		(start 133.59257 -121.536968)
		(end 133.54812 -121.492518)
		(width 0.12954)
		(layer "F.Cu")
		(net "HP_OCP_V3_2_EN")
	)
	(segment
		(start 132.60832 -120.89384)
		(end 132.314696 -120.600216)
		(width 0.12954)
		(layer "F.Cu")
		(net "HP_OCP_V3_2_EN")
	)
	(segment
		(start 133.3627 -120.89384)
		(end 132.60832 -120.89384)
		(width 0.12954)
		(layer "F.Cu")
		(net "HP_OCP_V3_2_EN")
	)
	(via
		(at 134.78002 -121.536968)
		(size 0.762)
		(drill 0.381)
		(layers "F.Cu" "B.Cu")
		(net "HP_OCP_V3_2_EN")
	)
	(segment
		(start 384.91795 -34.566098)
		(end 383.8448 -33.492948)
		(width 0.12954)
		(layer "F.Cu")
		(net "HP_LVC3_OCP_V3_1_PWRGD")
	)
	(segment
		(start 384.41884 -32.918908)
		(end 385.261104 -32.918908)
		(width 0.12954)
		(layer "F.Cu")
		(net "HP_LVC3_OCP_V3_1_PWRGD")
	)
	(segment
		(start 384.91795 -34.585148)
		(end 384.91795 -34.566098)
		(width 0.12954)
		(layer "F.Cu")
		(net "HP_LVC3_OCP_V3_1_PWRGD")
	)
	(segment
		(start 383.8448 -33.492948)
		(end 384.41884 -32.918908)
		(width 0.12954)
		(layer "F.Cu")
		(net "HP_LVC3_OCP_V3_1_PWRGD")
	)
	(via
		(at 383.8448 -33.492948)
		(size 0.762)
		(drill 0.381)
		(layers "F.Cu" "B.Cu")
		(net "HP_LVC3_OCP_V3_1_PWRGD")
	)
	(segment
		(start 459.214474 -102.41915)
		(end 458.637386 -102.996238)
		(width 0.12954)
		(layer "F.Cu")
		(net "HP_LVC3_OCP_V3_1_PRSNT2_N_R")
	)
	(segment
		(start 458.637386 -104.29621)
		(end 458.254354 -104.29621)
		(width 0.12954)
		(layer "F.Cu")
		(net "HP_LVC3_OCP_V3_1_PRSNT2_N_R")
	)
	(segment
		(start 459.075282 -108.020612)
		(end 458.723492 -107.668822)
		(width 0.12954)
		(layer "F.Cu")
		(net "HP_LVC3_OCP_V3_1_PRSNT2_N_R")
	)
	(segment
		(start 458.15885 -102.996238)
		(end 458.637386 -102.996238)
		(width 0.12954)
		(layer "F.Cu")
		(net "HP_LVC3_OCP_V3_1_PRSNT2_N_R")
	)
	(segment
		(start 457.937616 -106.519472)
		(end 457.937616 -107.408472)
		(width 0.12954)
		(layer "F.Cu")
		(net "HP_LVC3_OCP_V3_1_PRSNT2_N_R")
	)
	(segment
		(start 460.096616 -102.41915)
		(end 459.214474 -102.41915)
		(width 0.12954)
		(layer "F.Cu")
		(net "HP_LVC3_OCP_V3_1_PRSNT2_N_R")
	)
	(segment
		(start 461.193896 -108.256324)
		(end 461.193896 -108.694728)
		(width 0.12954)
		(layer "F.Cu")
		(net "HP_LVC3_OCP_V3_1_PRSNT2_N_R")
	)
	(segment
		(start 457.937616 -103.979472)
		(end 457.937616 -103.217472)
		(width 0.12954)
		(layer "F.Cu")
		(net "HP_LVC3_OCP_V3_1_PRSNT2_N_R")
	)
	(segment
		(start 458.637386 -104.704134)
		(end 458.634592 -104.706928)
		(width 0.12954)
		(layer "F.Cu")
		(net "HP_LVC3_OCP_V3_1_PRSNT2_N_R")
	)
	(segment
		(start 462.56956 -108.06176)
		(end 462.44256 -108.18876)
		(width 0.12954)
		(layer "F.Cu")
		(net "HP_LVC3_OCP_V3_1_PRSNT2_N_R")
	)
	(segment
		(start 459.660498 -108.694728)
		(end 459.075282 -108.109512)
		(width 0.12954)
		(layer "F.Cu")
		(net "HP_LVC3_OCP_V3_1_PRSNT2_N_R")
	)
	(segment
		(start 458.634592 -104.706928)
		(end 458.634592 -106.36885)
		(width 0.12954)
		(layer "F.Cu")
		(net "HP_LVC3_OCP_V3_1_PRSNT2_N_R")
	)
	(segment
		(start 458.197966 -107.668822)
		(end 458.634592 -107.668822)
		(width 0.12954)
		(layer "F.Cu")
		(net "HP_LVC3_OCP_V3_1_PRSNT2_N_R")
	)
	(segment
		(start 461.993996 -106.027728)
		(end 462.44256 -106.027728)
		(width 0.12954)
		(layer "F.Cu")
		(net "HP_LVC3_OCP_V3_1_PRSNT2_N_R")
	)
	(segment
		(start 458.637386 -104.29621)
		(end 458.637386 -104.704134)
		(width 0.12954)
		(layer "F.Cu")
		(net "HP_LVC3_OCP_V3_1_PRSNT2_N_R")
	)
	(segment
		(start 459.075282 -108.109512)
		(end 459.075282 -108.020612)
		(width 0.12954)
		(layer "F.Cu")
		(net "HP_LVC3_OCP_V3_1_PRSNT2_N_R")
	)
	(segment
		(start 461.193896 -108.694728)
		(end 459.660498 -108.694728)
		(width 0.12954)
		(layer "F.Cu")
		(net "HP_LVC3_OCP_V3_1_PRSNT2_N_R")
	)
	(segment
		(start 461.320896 -102.41915)
		(end 460.096616 -102.41915)
		(width 0.12954)
		(layer "F.Cu")
		(net "HP_LVC3_OCP_V3_1_PRSNT2_N_R")
	)
	(segment
		(start 457.937616 -103.217472)
		(end 458.15885 -102.996238)
		(width 0.12954)
		(layer "F.Cu")
		(net "HP_LVC3_OCP_V3_1_PRSNT2_N_R")
	)
	(segment
		(start 462.56956 -106.154728)
		(end 462.56956 -108.06176)
		(width 0.12954)
		(layer "F.Cu")
		(net "HP_LVC3_OCP_V3_1_PRSNT2_N_R")
	)
	(segment
		(start 457.937616 -107.408472)
		(end 458.197966 -107.668822)
		(width 0.12954)
		(layer "F.Cu")
		(net "HP_LVC3_OCP_V3_1_PRSNT2_N_R")
	)
	(segment
		(start 458.723492 -107.668822)
		(end 458.634592 -107.668822)
		(width 0.12954)
		(layer "F.Cu")
		(net "HP_LVC3_OCP_V3_1_PRSNT2_N_R")
	)
	(segment
		(start 458.088238 -106.36885)
		(end 457.937616 -106.519472)
		(width 0.12954)
		(layer "F.Cu")
		(net "HP_LVC3_OCP_V3_1_PRSNT2_N_R")
	)
	(segment
		(start 458.254354 -104.29621)
		(end 457.937616 -103.979472)
		(width 0.12954)
		(layer "F.Cu")
		(net "HP_LVC3_OCP_V3_1_PRSNT2_N_R")
	)
	(segment
		(start 458.634592 -106.36885)
		(end 458.088238 -106.36885)
		(width 0.12954)
		(layer "F.Cu")
		(net "HP_LVC3_OCP_V3_1_PRSNT2_N_R")
	)
	(segment
		(start 462.44256 -106.027728)
		(end 462.56956 -106.154728)
		(width 0.12954)
		(layer "F.Cu")
		(net "HP_LVC3_OCP_V3_1_PRSNT2_N_R")
	)
	(segment
		(start 461.26146 -108.18876)
		(end 461.193896 -108.256324)
		(width 0.12954)
		(layer "F.Cu")
		(net "HP_LVC3_OCP_V3_1_PRSNT2_N_R")
	)
	(segment
		(start 462.44256 -108.18876)
		(end 461.26146 -108.18876)
		(width 0.12954)
		(layer "F.Cu")
		(net "HP_LVC3_OCP_V3_1_PRSNT2_N_R")
	)
	(via
		(at 460.096616 -102.41915)
		(size 0.762)
		(drill 0.381)
		(layers "F.Cu" "B.Cu")
		(net "HP_LVC3_OCP_V3_1_PRSNT2_N_R")
	)
	(segment
		(start 459.92288 -109.464348)
		(end 459.691994 -109.233462)
		(width 0.12954)
		(layer "F.Cu")
		(net "HP_LVC3_OCP_V3_1_PRSNT2_N")
	)
	(segment
		(start 461.530446 -109.464348)
		(end 459.92288 -109.464348)
		(width 0.12954)
		(layer "F.Cu")
		(net "HP_LVC3_OCP_V3_1_PRSNT2_N")
	)
	(segment
		(start 450.26072 -111.879888)
		(end 450.01688 -111.636048)
		(width 0.12954)
		(layer "F.Cu")
		(net "HP_LVC3_OCP_V3_1_PRSNT2_N")
	)
	(segment
		(start 463.271616 -110.251748)
		(end 463.236056 -110.287308)
		(width 0.12954)
		(layer "F.Cu")
		(net "HP_LVC3_OCP_V3_1_PRSNT2_N")
	)
	(segment
		(start 453.944482 -113.99139)
		(end 453.36968 -113.416588)
		(width 0.12954)
		(layer "F.Cu")
		(net "HP_LVC3_OCP_V3_1_PRSNT2_N")
	)
	(segment
		(start 453.36968 -113.416588)
		(end 453.36968 -112.438688)
		(width 0.12954)
		(layer "F.Cu")
		(net "HP_LVC3_OCP_V3_1_PRSNT2_N")
	)
	(segment
		(start 450.85254 -109.233462)
		(end 451.658228 -109.233462)
		(width 0.12954)
		(layer "F.Cu")
		(net "HP_LVC3_OCP_V3_1_PRSNT2_N")
	)
	(segment
		(start 454.798684 -113.99139)
		(end 453.944482 -113.99139)
		(width 0.12954)
		(layer "F.Cu")
		(net "HP_LVC3_OCP_V3_1_PRSNT2_N")
	)
	(segment
		(start 450.01688 -111.173768)
		(end 450.47662 -110.714028)
		(width 0.12954)
		(layer "F.Cu")
		(net "HP_LVC3_OCP_V3_1_PRSNT2_N")
	)
	(segment
		(start 462.414874 -108.694728)
		(end 462.541874 -108.567728)
		(width 0.12954)
		(layer "F.Cu")
		(net "HP_LVC3_OCP_V3_1_PRSNT2_N")
	)
	(segment
		(start 452.81088 -111.879888)
		(end 450.26072 -111.879888)
		(width 0.12954)
		(layer "F.Cu")
		(net "HP_LVC3_OCP_V3_1_PRSNT2_N")
	)
	(segment
		(start 463.271616 -108.567728)
		(end 463.271616 -110.251748)
		(width 0.12954)
		(layer "F.Cu")
		(net "HP_LVC3_OCP_V3_1_PRSNT2_N")
	)
	(segment
		(start 461.993996 -108.694728)
		(end 462.414874 -108.694728)
		(width 0.12954)
		(layer "F.Cu")
		(net "HP_LVC3_OCP_V3_1_PRSNT2_N")
	)
	(segment
		(start 461.993996 -109.000798)
		(end 461.530446 -109.464348)
		(width 0.12954)
		(layer "F.Cu")
		(net "HP_LVC3_OCP_V3_1_PRSNT2_N")
	)
	(segment
		(start 453.36968 -112.438688)
		(end 452.81088 -111.879888)
		(width 0.12954)
		(layer "F.Cu")
		(net "HP_LVC3_OCP_V3_1_PRSNT2_N")
	)
	(segment
		(start 459.691994 -109.233462)
		(end 451.658228 -109.233462)
		(width 0.12954)
		(layer "F.Cu")
		(net "HP_LVC3_OCP_V3_1_PRSNT2_N")
	)
	(segment
		(start 450.01688 -111.636048)
		(end 450.01688 -111.173768)
		(width 0.12954)
		(layer "F.Cu")
		(net "HP_LVC3_OCP_V3_1_PRSNT2_N")
	)
	(segment
		(start 450.47662 -110.714028)
		(end 450.47662 -109.609382)
		(width 0.12954)
		(layer "F.Cu")
		(net "HP_LVC3_OCP_V3_1_PRSNT2_N")
	)
	(segment
		(start 462.541874 -108.567728)
		(end 463.271616 -108.567728)
		(width 0.12954)
		(layer "F.Cu")
		(net "HP_LVC3_OCP_V3_1_PRSNT2_N")
	)
	(segment
		(start 461.993996 -108.694728)
		(end 461.993996 -109.000798)
		(width 0.12954)
		(layer "F.Cu")
		(net "HP_LVC3_OCP_V3_1_PRSNT2_N")
	)
	(segment
		(start 450.47662 -109.609382)
		(end 450.85254 -109.233462)
		(width 0.12954)
		(layer "F.Cu")
		(net "HP_LVC3_OCP_V3_1_PRSNT2_N")
	)
	(via
		(at 463.271616 -108.567728)
		(size 0.762)
		(drill 0.381)
		(layers "F.Cu" "B.Cu")
		(net "HP_LVC3_OCP_V3_1_PRSNT2_N")
	)
	(segment
		(start 449.45808 -110.183676)
		(end 449.43014 -110.211616)
		(width 0.12954)
		(layer "F.Cu")
		(net "HP_LVC3_OCP_V3_1_PRSNT2")
	)
	(segment
		(start 447.47688 -111.338868)
		(end 447.93662 -111.338868)
		(width 0.12954)
		(layer "F.Cu")
		(net "HP_LVC3_OCP_V3_1_PRSNT2")
	)
	(segment
		(start 449.43014 -110.211616)
		(end 449.43014 -115.312444)
		(width 0.12954)
		(layer "F.Cu")
		(net "HP_LVC3_OCP_V3_1_PRSNT2")
	)
	(segment
		(start 449.091812 -110.183676)
		(end 449.45808 -110.183676)
		(width 0.12954)
		(layer "F.Cu")
		(net "HP_LVC3_OCP_V3_1_PRSNT2")
	)
	(segment
		(start 447.094864 -110.038134)
		(end 447.094864 -110.956852)
		(width 0.12954)
		(layer "F.Cu")
		(net "HP_LVC3_OCP_V3_1_PRSNT2")
	)
	(segment
		(start 447.93662 -111.338868)
		(end 449.091812 -110.183676)
		(width 0.12954)
		(layer "F.Cu")
		(net "HP_LVC3_OCP_V3_1_PRSNT2")
	)
	(segment
		(start 449.45808 -110.183422)
		(end 449.45808 -110.183676)
		(width 0.12954)
		(layer "F.Cu")
		(net "HP_LVC3_OCP_V3_1_PRSNT2")
	)
	(segment
		(start 447.094864 -110.956852)
		(end 447.47688 -111.338868)
		(width 0.12954)
		(layer "F.Cu")
		(net "HP_LVC3_OCP_V3_1_PRSNT2")
	)
	(via
		(at 447.47688 -111.338868)
		(size 0.762)
		(drill 0.381)
		(layers "F.Cu" "B.Cu")
		(net "HP_LVC3_OCP_V3_1_PRSNT2")
	)
	(segment
		(start 456.185524 -113.341404)
		(end 458.84084 -110.686088)
		(width 0.12954)
		(layer "F.Cu")
		(net "TP_PCA9555_0_P5")
	)
	(segment
		(start 458.84084 -110.686088)
		(end 458.84084 -109.982508)
		(width 0.12954)
		(layer "F.Cu")
		(net "TP_PCA9555_0_P5")
	)
	(segment
		(start 454.798684 -113.341404)
		(end 456.185524 -113.341404)
		(width 0.12954)
		(layer "F.Cu")
		(net "TP_PCA9555_0_P5")
	)
	(via
		(at 458.84084 -109.982508)
		(size 0.762)
		(drill 0.381)
		(layers "F.Cu" "B.Cu")
		(net "TP_PCA9555_0_P5")
	)
	(segment
		(start 421.54856 -112.753648)
		(end 448.321176 -112.753648)
		(width 0.12954)
		(layer "F.Cu")
		(net "HP_LVC3_OCP_V3_1_EN")
	)
	(segment
		(start 457.882498 -42.814748)
		(end 457.12126 -42.05351)
		(width 0.12954)
		(layer "F.Cu")
		(net "HP_LVC3_OCP_V3_1_EN")
	)
	(segment
		(start 461.557624 -38.284404)
		(end 461.31988 -38.522148)
		(width 0.12954)
		(layer "F.Cu")
		(net "HP_LVC3_OCP_V3_1_EN")
	)
	(segment
		(start 420.14394 -110.280958)
		(end 420.14394 -111.349028)
		(width 0.12954)
		(layer "F.Cu")
		(net "HP_LVC3_OCP_V3_1_EN")
	)
	(segment
		(start 457.12126 -42.05351)
		(end 452.743824 -42.05351)
		(width 0.12954)
		(layer "F.Cu")
		(net "HP_LVC3_OCP_V3_1_EN")
	)
	(segment
		(start 451.641972 -43.155362)
		(end 450.8373 -43.155362)
		(width 0.12954)
		(layer "F.Cu")
		(net "HP_LVC3_OCP_V3_1_EN")
	)
	(segment
		(start 420.14394 -109.671358)
		(end 420.14394 -110.280958)
		(width 0.12954)
		(layer "F.Cu")
		(net "HP_LVC3_OCP_V3_1_EN")
	)
	(segment
		(start 448.321176 -112.753648)
		(end 448.48018 -112.912652)
		(width 0.12954)
		(layer "F.Cu")
		(net "HP_LVC3_OCP_V3_1_EN")
	)
	(segment
		(start 461.06588 -42.814748)
		(end 457.882498 -42.814748)
		(width 0.12954)
		(layer "F.Cu")
		(net "HP_LVC3_OCP_V3_1_EN")
	)
	(segment
		(start 461.31988 -42.560748)
		(end 461.06588 -42.814748)
		(width 0.12954)
		(layer "F.Cu")
		(net "HP_LVC3_OCP_V3_1_EN")
	)
	(segment
		(start 461.31988 -38.522148)
		(end 461.31988 -42.560748)
		(width 0.12954)
		(layer "F.Cu")
		(net "HP_LVC3_OCP_V3_1_EN")
	)
	(segment
		(start 450.8373 -43.155362)
		(end 450.8373 -42.517568)
		(width 0.12954)
		(layer "F.Cu")
		(net "HP_LVC3_OCP_V3_1_EN")
	)
	(segment
		(start 452.743824 -42.05351)
		(end 451.641972 -43.155362)
		(width 0.12954)
		(layer "F.Cu")
		(net "HP_LVC3_OCP_V3_1_EN")
	)
	(segment
		(start 444.733172 -32.573468)
		(end 446.6082 -32.573468)
		(width 0.12954)
		(layer "F.Cu")
		(net "HP_LVC3_OCP_V3_1_EN")
	)
	(segment
		(start 462.143094 -38.284404)
		(end 461.557624 -38.284404)
		(width 0.12954)
		(layer "F.Cu")
		(net "HP_LVC3_OCP_V3_1_EN")
	)
	(segment
		(start 420.14394 -111.349028)
		(end 421.54856 -112.753648)
		(width 0.12954)
		(layer "F.Cu")
		(net "HP_LVC3_OCP_V3_1_EN")
	)
	(via
		(at 446.6082 -32.573468)
		(size 0.508)
		(drill 0.254)
		(layers "F.Cu" "B.Cu")
		(net "HP_LVC3_OCP_V3_1_EN")
	)
	(via
		(at 420.14394 -110.280958)
		(size 0.508)
		(drill 0.254)
		(layers "F.Cu" "B.Cu")
		(net "HP_LVC3_OCP_V3_1_EN")
	)
	(via
		(at 450.8373 -42.517568)
		(size 0.508)
		(drill 0.254)
		(layers "F.Cu" "B.Cu")
		(net "HP_LVC3_OCP_V3_1_EN")
	)
	(segment
		(start 420.4081 -102.775258)
		(end 419.23208 -101.599238)
		(width 0.12954)
		(layer "B.Cu")
		(net "HP_LVC3_OCP_V3_1_EN")
	)
	(segment
		(start 420.4081 -110.016798)
		(end 420.4081 -102.775258)
		(width 0.12954)
		(layer "B.Cu")
		(net "HP_LVC3_OCP_V3_1_EN")
	)
	(segment
		(start 437.926988 -51.41214)
		(end 445.19977 -44.139358)
		(width 0.12954)
		(layer "B.Cu")
		(net "HP_LVC3_OCP_V3_1_EN")
	)
	(segment
		(start 437.481726 -59.605672)
		(end 437.926988 -59.16041)
		(width 0.12954)
		(layer "B.Cu")
		(net "HP_LVC3_OCP_V3_1_EN")
	)
	(segment
		(start 420.14394 -110.280958)
		(end 420.4081 -110.016798)
		(width 0.12954)
		(layer "B.Cu")
		(net "HP_LVC3_OCP_V3_1_EN")
	)
	(segment
		(start 419.23208 -97.190052)
		(end 437.481726 -78.940406)
		(width 0.12954)
		(layer "B.Cu")
		(net "HP_LVC3_OCP_V3_1_EN")
	)
	(segment
		(start 437.926988 -59.16041)
		(end 437.926988 -51.41214)
		(width 0.12954)
		(layer "B.Cu")
		(net "HP_LVC3_OCP_V3_1_EN")
	)
	(segment
		(start 419.23208 -101.599238)
		(end 419.23208 -97.190052)
		(width 0.12954)
		(layer "B.Cu")
		(net "HP_LVC3_OCP_V3_1_EN")
	)
	(segment
		(start 446.82029 -44.139358)
		(end 447.9163 -43.043348)
		(width 0.12954)
		(layer "B.Cu")
		(net "HP_LVC3_OCP_V3_1_EN")
	)
	(segment
		(start 450.451474 -42.517568)
		(end 450.8373 -42.517568)
		(width 0.12954)
		(layer "B.Cu")
		(net "HP_LVC3_OCP_V3_1_EN")
	)
	(segment
		(start 447.9163 -43.043348)
		(end 449.925694 -43.043348)
		(width 0.12954)
		(layer "B.Cu")
		(net "HP_LVC3_OCP_V3_1_EN")
	)
	(segment
		(start 437.481726 -78.940406)
		(end 437.481726 -59.605672)
		(width 0.12954)
		(layer "B.Cu")
		(net "HP_LVC3_OCP_V3_1_EN")
	)
	(segment
		(start 449.925694 -43.043348)
		(end 450.451474 -42.517568)
		(width 0.12954)
		(layer "B.Cu")
		(net "HP_LVC3_OCP_V3_1_EN")
	)
	(segment
		(start 445.19977 -44.139358)
		(end 446.82029 -44.139358)
		(width 0.12954)
		(layer "B.Cu")
		(net "HP_LVC3_OCP_V3_1_EN")
	)
	(segment
		(start 450.8373 -42.517568)
		(end 446.6082 -38.288468)
		(width 0.127)
		(layer "In2.Cu")
		(net "HP_LVC3_OCP_V3_1_EN")
	)
	(segment
		(start 446.6082 -38.288468)
		(end 446.6082 -32.573468)
		(width 0.127)
		(layer "In2.Cu")
		(net "HP_LVC3_OCP_V3_1_EN")
	)
	(segment
		(start 463.398616 -102.41915)
		(end 464.424776 -101.39299)
		(width 0.12954)
		(layer "F.Cu")
		(net "HP_LVC3_OCP_V3_1_ATTN_OUT_SW_N")
	)
	(segment
		(start 454.802748 -114.641376)
		(end 454.848976 -114.595148)
		(width 0.12954)
		(layer "F.Cu")
		(net "HP_LVC3_OCP_V3_1_ATTN_OUT_SW_N")
	)
	(segment
		(start 454.798684 -114.641376)
		(end 454.802748 -114.641376)
		(width 0.12954)
		(layer "F.Cu")
		(net "HP_LVC3_OCP_V3_1_ATTN_OUT_SW_N")
	)
	(segment
		(start 454.848976 -114.595148)
		(end 456.18908 -114.595148)
		(width 0.12954)
		(layer "F.Cu")
		(net "HP_LVC3_OCP_V3_1_ATTN_OUT_SW_N")
	)
	(segment
		(start 464.643216 -103.179372)
		(end 464.643216 -101.39299)
		(width 0.12954)
		(layer "F.Cu")
		(net "HP_LVC3_OCP_V3_1_ATTN_OUT_SW_N")
	)
	(segment
		(start 464.424776 -101.39299)
		(end 464.643216 -101.39299)
		(width 0.12954)
		(layer "F.Cu")
		(net "HP_LVC3_OCP_V3_1_ATTN_OUT_SW_N")
	)
	(segment
		(start 464.676236 -103.212392)
		(end 464.643216 -103.179372)
		(width 0.12954)
		(layer "F.Cu")
		(net "HP_LVC3_OCP_V3_1_ATTN_OUT_SW_N")
	)
	(segment
		(start 462.120996 -102.41915)
		(end 463.398616 -102.41915)
		(width 0.12954)
		(layer "F.Cu")
		(net "HP_LVC3_OCP_V3_1_ATTN_OUT_SW_N")
	)
	(via
		(at 464.676236 -103.212392)
		(size 0.508)
		(drill 0.254)
		(layers "F.Cu" "B.Cu")
		(net "HP_LVC3_OCP_V3_1_ATTN_OUT_SW_N")
	)
	(via
		(at 463.398616 -102.41915)
		(size 0.762)
		(drill 0.381)
		(layers "F.Cu" "B.Cu")
		(net "HP_LVC3_OCP_V3_1_ATTN_OUT_SW_N")
	)
	(via
		(at 456.18908 -114.595148)
		(size 0.508)
		(drill 0.254)
		(layers "F.Cu" "B.Cu")
		(net "HP_LVC3_OCP_V3_1_ATTN_OUT_SW_N")
	)
	(segment
		(start 463.9056 -104.4702)
		(end 463.9056 -106.299)
		(width 0.127)
		(layer "In2.Cu")
		(net "HP_LVC3_OCP_V3_1_ATTN_OUT_SW_N")
	)
	(segment
		(start 463.9056 -106.299)
		(end 463.234786 -106.969814)
		(width 0.127)
		(layer "In2.Cu")
		(net "HP_LVC3_OCP_V3_1_ATTN_OUT_SW_N")
	)
	(segment
		(start 464.676236 -103.212392)
		(end 464.676236 -103.699564)
		(width 0.127)
		(layer "In2.Cu")
		(net "HP_LVC3_OCP_V3_1_ATTN_OUT_SW_N")
	)
	(segment
		(start 460.918814 -106.969814)
		(end 456.18908 -111.699548)
		(width 0.127)
		(layer "In2.Cu")
		(net "HP_LVC3_OCP_V3_1_ATTN_OUT_SW_N")
	)
	(segment
		(start 464.676236 -103.699564)
		(end 463.9056 -104.4702)
		(width 0.127)
		(layer "In2.Cu")
		(net "HP_LVC3_OCP_V3_1_ATTN_OUT_SW_N")
	)
	(segment
		(start 456.18908 -111.699548)
		(end 456.18908 -114.595148)
		(width 0.127)
		(layer "In2.Cu")
		(net "HP_LVC3_OCP_V3_1_ATTN_OUT_SW_N")
	)
	(segment
		(start 463.234786 -106.969814)
		(end 460.918814 -106.969814)
		(width 0.127)
		(layer "In2.Cu")
		(net "HP_LVC3_OCP_V3_1_ATTN_OUT_SW_N")
	)
	(segment
		(start 433.484782 -239.81664)
		(end 434.589682 -239.81664)
		(width 0.381)
		(layer "F.Cu")
		(net "GND")
	)
	(segment
		(start 11.135614 -314.616592)
		(end 12.240514 -314.616592)
		(width 0.381)
		(layer "F.Cu")
		(net "GND")
	)
	(segment
		(start 340.78418 -228.1809)
		(end 340.784434 -228.180646)
		(width 0.2032)
		(layer "F.Cu")
		(net "GND")
	)
	(segment
		(start 380.25578 -216.250774)
		(end 380.256034 -216.25052)
		(width 0.254)
		(layer "F.Cu")
		(net "GND")
	)
	(segment
		(start 281.707082 -291.666676)
		(end 282.811982 -291.666676)
		(width 0.381)
		(layer "F.Cu")
		(net "GND")
	)
	(segment
		(start 425.940982 -202.416664)
		(end 427.045882 -202.416664)
		(width 0.381)
		(layer "F.Cu")
		(net "GND")
	)
	(segment
		(start 289.250882 -238.116618)
		(end 290.355782 -238.116618)
		(width 0.381)
		(layer "F.Cu")
		(net "GND")
	)
	(segment
		(start 428.279814 -307.816758)
		(end 429.384714 -307.816758)
		(width 0.381)
		(layer "F.Cu")
		(net "GND")
	)
	(segment
		(start 151.8158 -39.710868)
		(end 152.075896 -39.450772)
		(width 0.3556)
		(layer "F.Cu")
		(net "GND")
	)
	(segment
		(start 89.664794 -260.708902)
		(end 89.664794 -261.244842)
		(width 0.2032)
		(layer "F.Cu")
		(net "GND")
	)
	(segment
		(start 345.483434 -229.808532)
		(end 345.483434 -229.272846)
		(width 0.2032)
		(layer "F.Cu")
		(net "GND")
	)
	(segment
		(start 38.315646 -279.766776)
		(end 37.210746 -279.766776)
		(width 0.381)
		(layer "F.Cu")
		(net "GND")
	)
	(segment
		(start 351.702116 -284.033468)
		(end 351.701862 -284.033722)
		(width 0.254)
		(layer "F.Cu")
		(net "GND")
	)
	(segment
		(start 338.099908 -49.650396)
		(end 338.499958 -50.050446)
		(width 0.2032)
		(layer "F.Cu")
		(net "GND")
	)
	(segment
		(start 178.69408 -30.33776)
		(end 178.69408 -31.12516)
		(width 0.17272)
		(layer "F.Cu")
		(net "GND")
	)
	(segment
		(start 256.080514 -270.416782)
		(end 257.185414 -270.416782)
		(width 0.381)
		(layer "F.Cu")
		(net "GND")
	)
	(segment
		(start 91.074494 -268.033754)
		(end 91.074748 -268.034008)
		(width 0.2032)
		(layer "F.Cu")
		(net "GND")
	)
	(segment
		(start 219.94495 -48.79975)
		(end 219.67952 -48.53432)
		(width 0.3556)
		(layer "F.Cu")
		(net "GND")
	)
	(segment
		(start 191.983614 -275.516594)
		(end 193.088514 -275.516594)
		(width 0.381)
		(layer "F.Cu")
		(net "GND")
	)
	(segment
		(start 99.532694 -253.383796)
		(end 99.532694 -253.919482)
		(width 0.2032)
		(layer "F.Cu")
		(net "GND")
	)
	(segment
		(start 254.975614 -272.116804)
		(end 256.080514 -272.116804)
		(width 0.381)
		(layer "F.Cu")
		(net "GND")
	)
	(segment
		(start 109.870494 -274.54479)
		(end 109.870494 -275.08073)
		(width 0.254)
		(layer "F.Cu")
		(net "GND")
	)
	(segment
		(start 88.615266 -217.600276)
		(end 88.615266 -217.06459)
		(width 0.2032)
		(layer "F.Cu")
		(net "GND")
	)
	(segment
		(start 167.461946 -295.06672)
		(end 166.357046 -295.06672)
		(width 0.381)
		(layer "F.Cu")
		(net "GND")
	)
	(segment
		(start 263.624314 -223.666558)
		(end 264.729214 -223.666558)
		(width 0.381)
		(layer "F.Cu")
		(net "GND")
	)
	(segment
		(start 332.796134 -246.900446)
		(end 332.326234 -247.178322)
		(width 0.2032)
		(layer "F.Cu")
		(net "GND")
	)
	(segment
		(start 350.65208 -230.622348)
		(end 350.65208 -230.086662)
		(width 0.2032)
		(layer "F.Cu")
		(net "GND")
	)
	(segment
		(start 11.135614 -264.466578)
		(end 12.240514 -264.466578)
		(width 0.381)
		(layer "F.Cu")
		(net "GND")
	)
	(segment
		(start 115.039648 -273.730974)
		(end 115.039394 -274.266914)
		(width 0.254)
		(layer "F.Cu")
		(net "GND")
	)
	(segment
		(start 181.444646 -225.36658)
		(end 182.549546 -225.36658)
		(width 0.381)
		(layer "F.Cu")
		(net "GND")
	)
	(segment
		(start 132.315712 -216.250774)
		(end 132.315966 -216.25052)
		(width 0.254)
		(layer "F.Cu")
		(net "GND")
	)
	(segment
		(start 18.679414 -280.61666)
		(end 19.784314 -280.61666)
		(width 0.381)
		(layer "F.Cu")
		(net "GND")
	)
	(segment
		(start 123.967494 -281.05608)
		(end 123.967494 -281.591512)
		(width 0.254)
		(layer "F.Cu")
		(net "GND")
	)
	(segment
		(start 439.923682 -194.766692)
		(end 441.028582 -194.766692)
		(width 0.381)
		(layer "F.Cu")
		(net "GND")
	)
	(segment
		(start 22.123146 -236.416596)
		(end 23.228046 -236.416596)
		(width 0.381)
		(layer "F.Cu")
		(net "GND")
	)
	(segment
		(start 336.085434 -229.272846)
		(end 336.085434 -229.808786)
		(width 0.2032)
		(layer "F.Cu")
		(net "GND")
	)
	(segment
		(start 12.240514 -235.566712)
		(end 11.135614 -235.566712)
		(width 0.381)
		(layer "F.Cu")
		(net "GND")
	)
	(segment
		(start 412.220664 -207.51673)
		(end 410.853382 -207.51673)
		(width 0.381)
		(layer "F.Cu")
		(net "GND")
	)
	(segment
		(start 208.199736 -68.503292)
		(end 206.7306 -68.503292)
		(width 0.3556)
		(layer "F.Cu")
		(net "GND")
	)
	(segment
		(start 383.545334 -238.225584)
		(end 383.545334 -238.761524)
		(width 0.254)
		(layer "F.Cu")
		(net "GND")
	)
	(segment
		(start 200.632314 -295.916604)
		(end 201.737214 -295.916604)
		(width 0.381)
		(layer "F.Cu")
		(net "GND")
	)
	(segment
		(start 334.899508 -47.250096)
		(end 335.299558 -47.650146)
		(width 0.2032)
		(layer "F.Cu")
		(net "GND")
	)
	(segment
		(start 102.822248 -274.26666)
		(end 102.821994 -274.266914)
		(width 0.2032)
		(layer "F.Cu")
		(net "GND")
	)
	(segment
		(start 93.424248 -283.497782)
		(end 93.424248 -284.033468)
		(width 0.254)
		(layer "F.Cu")
		(net "GND")
	)
	(segment
		(start 383.07518 -223.297496)
		(end 383.07518 -222.76181)
		(width 0.254)
		(layer "F.Cu")
		(net "GND")
	)
	(segment
		(start 278.711914 -289.11677)
		(end 279.816814 -289.11677)
		(width 0.381)
		(layer "F.Cu")
		(net "GND")
	)
	(segment
		(start 178.000914 -312.91657)
		(end 179.105814 -312.91657)
		(width 0.381)
		(layer "F.Cu")
		(net "GND")
	)
	(segment
		(start 405.648414 -298.466764)
		(end 406.753314 -298.466764)
		(width 0.381)
		(layer "F.Cu")
		(net "GND")
	)
	(segment
		(start 343.133934 -235.506006)
		(end 343.13368 -235.505752)
		(width 0.2032)
		(layer "F.Cu")
		(net "GND")
	)
	(segment
		(start 452.016114 -195.616576)
		(end 450.911214 -195.616576)
		(width 0.381)
		(layer "F.Cu")
		(net "GND")
	)
	(segment
		(start 421.840914 -313.766708)
		(end 420.736014 -313.766708)
		(width 0.381)
		(layer "F.Cu")
		(net "GND")
	)
	(segment
		(start 293.799514 -195.616576)
		(end 292.694614 -195.616576)
		(width 0.381)
		(layer "F.Cu")
		(net "GND")
	)
	(segment
		(start 307.782214 -210.916774)
		(end 308.887114 -210.916774)
		(width 0.381)
		(layer "F.Cu")
		(net "GND")
	)
	(segment
		(start 335.14538 -247.714262)
		(end 335.14538 -247.178576)
		(width 0.2032)
		(layer "F.Cu")
		(net "GND")
	)
	(segment
		(start 115.869466 -214.344758)
		(end 115.869466 -213.732618)
		(width 0.254)
		(layer "F.Cu")
		(net "GND")
	)
	(segment
		(start 143.5735 -107.795568)
		(end 142.48384 -107.795568)
		(width 0.3556)
		(layer "F.Cu")
		(net "GND")
	)
	(segment
		(start 56.398414 -299.316648)
		(end 57.503314 -299.316648)
		(width 0.381)
		(layer "F.Cu")
		(net "GND")
	)
	(segment
		(start 102.73665 -393.685268)
		(end 102.73665 -394.322808)
		(width 0.3556)
		(layer "F.Cu")
		(net "GND")
	)
	(segment
		(start 158.813246 -199.01662)
		(end 159.918146 -199.01662)
		(width 0.381)
		(layer "F.Cu")
		(net "GND")
	)
	(segment
		(start 261.285482 -299.316648)
		(end 260.180582 -299.316648)
		(width 0.381)
		(layer "F.Cu")
		(net "GND")
	)
	(segment
		(start 410.853382 -202.416664)
		(end 411.958282 -202.416664)
		(width 0.381)
		(layer "F.Cu")
		(net "GND")
	)
	(segment
		(start 368.978434 -220.041724)
		(end 368.978434 -219.506038)
		(width 0.254)
		(layer "F.Cu")
		(net "GND")
	)
	(segment
		(start 342.304116 -260.708902)
		(end 342.304116 -261.244588)
		(width 0.2032)
		(layer "F.Cu")
		(net "GND")
	)
	(segment
		(start 352.641916 -284.033468)
		(end 352.641662 -284.033722)
		(width 0.254)
		(layer "F.Cu")
		(net "GND")
	)
	(segment
		(start 341.72398 -237.947454)
		(end 341.724234 -237.947454)
		(width 0.254)
		(layer "F.Cu")
		(net "GND")
	)
	(segment
		(start 345.48318 -226.553268)
		(end 345.48318 -226.017582)
		(width 0.254)
		(layer "F.Cu")
		(net "GND")
	)
	(segment
		(start 427.045882 -277.216616)
		(end 425.940982 -277.216616)
		(width 0.381)
		(layer "F.Cu")
		(net "GND")
	)
	(segment
		(start 453.121014 -234.716574)
		(end 452.016114 -234.716574)
		(width 0.381)
		(layer "F.Cu")
		(net "GND")
	)
	(segment
		(start 104.591866 -224.111566)
		(end 104.591866 -223.575626)
		(width 0.2032)
		(layer "F.Cu")
		(net "GND")
	)
	(segment
		(start 7.035546 -301.866808)
		(end 8.140446 -301.866808)
		(width 0.381)
		(layer "F.Cu")
		(net "GND")
	)
	(segment
		(start 170.457114 -222.816674)
		(end 171.562014 -222.816674)
		(width 0.381)
		(layer "F.Cu")
		(net "GND")
	)
	(segment
		(start 27.328114 -269.566644)
		(end 28.433014 -269.566644)
		(width 0.381)
		(layer "F.Cu")
		(net "GND")
	)
	(segment
		(start 119.628666 -220.855794)
		(end 119.628666 -220.319854)
		(width 0.2032)
		(layer "F.Cu")
		(net "GND")
	)
	(segment
		(start 38.443408 -353.628452)
		(end 38.443408 -353.162616)
		(width 0.2032)
		(layer "F.Cu")
		(net "GND")
	)
	(segment
		(start 277.607014 -229.616762)
		(end 278.711914 -229.616762)
		(width 0.381)
		(layer "F.Cu")
		(net "GND")
	)
	(segment
		(start 132.895848 -283.497782)
		(end 132.895848 -284.033468)
		(width 0.254)
		(layer "F.Cu")
		(net "GND")
	)
	(segment
		(start 91.544648 -270.475456)
		(end 91.544648 -271.011142)
		(width 0.2032)
		(layer "F.Cu")
		(net "GND")
	)
	(segment
		(start 272.273014 -300.166786)
		(end 271.168114 -300.166786)
		(width 0.381)
		(layer "F.Cu")
		(net "GND")
	)
	(segment
		(start 425.940982 -303.566576)
		(end 424.836082 -303.566576)
		(width 0.381)
		(layer "F.Cu")
		(net "GND")
	)
	(segment
		(start 378.486162 -289.195002)
		(end 378.486162 -289.807142)
		(width 0.2032)
		(layer "F.Cu")
		(net "GND")
	)
	(segment
		(start 193.088514 -241.516662)
		(end 191.983614 -241.516662)
		(width 0.381)
		(layer "F.Cu")
		(net "GND")
	)
	(segment
		(start 263.624314 -307.816758)
		(end 264.729214 -307.816758)
		(width 0.381)
		(layer "F.Cu")
		(net "GND")
	)
	(segment
		(start 292.694614 -298.466764)
		(end 293.799514 -298.466764)
		(width 0.381)
		(layer "F.Cu")
		(net "GND")
	)
	(segment
		(start 373.787162 -271.289272)
		(end 373.787162 -271.825212)
		(width 0.2032)
		(layer "F.Cu")
		(net "GND")
	)
	(segment
		(start 51.064414 -272.966688)
		(end 49.959514 -272.966688)
		(width 0.381)
		(layer "F.Cu")
		(net "GND")
	)
	(segment
		(start 356.76078 -233.064304)
		(end 356.76078 -232.528618)
		(width 0.2032)
		(layer "F.Cu")
		(net "GND")
	)
	(segment
		(start 435.823614 -238.966756)
		(end 436.928514 -238.966756)
		(width 0.381)
		(layer "F.Cu")
		(net "GND")
	)
	(segment
		(start 88.360504 -37.709348)
		(end 87.573104 -37.709348)
		(width 0.3556)
		(layer "F.Cu")
		(net "GND")
	)
	(segment
		(start 53.403246 -231.316784)
		(end 54.508146 -231.316784)
		(width 0.381)
		(layer "F.Cu")
		(net "GND")
	)
	(segment
		(start 369.088162 -289.195002)
		(end 369.088162 -289.807142)
		(width 0.2032)
		(layer "F.Cu")
		(net "GND")
	)
	(segment
		(start 19.784314 -245.76659)
		(end 20.889214 -245.76659)
		(width 0.381)
		(layer "F.Cu")
		(net "GND")
	)
	(segment
		(start 361.45978 -223.297496)
		(end 361.45978 -222.76181)
		(width 0.254)
		(layer "F.Cu")
		(net "GND")
	)
	(segment
		(start 60.947046 -242.3668)
		(end 62.051946 -242.3668)
		(width 0.381)
		(layer "F.Cu")
		(net "GND")
	)
	(segment
		(start 373.787416 -281.056334)
		(end 373.787416 -281.59202)
		(width 0.254)
		(layer "F.Cu")
		(net "GND")
	)
	(segment
		(start 362.814362 -401.670012)
		(end 362.69676 -401.787614)
		(width 0.3556)
		(layer "F.Cu")
		(net "GND")
	)
	(segment
		(start 178.000914 -267.866622)
		(end 176.896014 -267.866622)
		(width 0.381)
		(layer "F.Cu")
		(net "GND")
	)
	(segment
		(start 256.080514 -306.116736)
		(end 257.185414 -306.116736)
		(width 0.381)
		(layer "F.Cu")
		(net "GND")
	)
	(segment
		(start 302.575214 -423.79392)
		(end 302.814482 -424.033188)
		(width 0.3556)
		(layer "F.Cu")
		(net "GND")
	)
	(segment
		(start 210.160108 -103.95204)
		(end 209.54492 -103.95204)
		(width 0.3556)
		(layer "F.Cu")
		(net "GND")
	)
	(segment
		(start 382.245362 -258.2672)
		(end 382.245362 -258.802886)
		(width 0.2032)
		(layer "F.Cu")
		(net "GND")
	)
	(segment
		(start 173.900846 -263.616694)
		(end 172.795946 -263.616694)
		(width 0.381)
		(layer "F.Cu")
		(net "GND")
	)
	(segment
		(start 26.223214 -314.616592)
		(end 27.328114 -314.616592)
		(width 0.381)
		(layer "F.Cu")
		(net "GND")
	)
	(segment
		(start 380.835916 -254.197612)
		(end 380.835916 -254.733552)
		(width 0.2032)
		(layer "F.Cu")
		(net "GND")
	)
	(segment
		(start 86.265766 -244.458744)
		(end 87.205312 -243.922804)
		(width 0.254)
		(layer "F.Cu")
		(net "GND")
	)
	(segment
		(start 174.155608 -105.775506)
		(end 173.755558 -105.375456)
		(width 0.3556)
		(layer "F.Cu")
		(net "GND")
	)
	(segment
		(start 137.594594 -273.730974)
		(end 137.153396 -273.475958)
		(width 0.254)
		(layer "F.Cu")
		(net "GND")
	)
	(segment
		(start 379.425962 -281.05608)
		(end 379.425962 -281.591512)
		(width 0.254)
		(layer "F.Cu")
		(net "GND")
	)
	(segment
		(start 424.836082 -241.516662)
		(end 425.940982 -241.516662)
		(width 0.381)
		(layer "F.Cu")
		(net "GND")
	)
	(segment
		(start 418.397182 -202.416664)
		(end 417.292282 -202.416664)
		(width 0.381)
		(layer "F.Cu")
		(net "GND")
	)
	(segment
		(start 457.221082 -310.366664)
		(end 456.116182 -310.366664)
		(width 0.381)
		(layer "F.Cu")
		(net "GND")
	)
	(segment
		(start 127.616966 -239.575086)
		(end 127.616966 -239.0394)
		(width 0.2032)
		(layer "F.Cu")
		(net "GND")
	)
	(segment
		(start 15.774924 -44.99991)
		(end 13.94968 -44.99991)
		(width 0.3556)
		(layer "F.Cu")
		(net "GND")
	)
	(segment
		(start 295.3766 -365.174784)
		(end 295.3766 -364.945168)
		(width 0.2032)
		(layer "F.Cu")
		(net "GND")
	)
	(segment
		(start 109.760512 -216.250774)
		(end 109.760766 -216.25052)
		(width 0.254)
		(layer "F.Cu")
		(net "GND")
	)
	(segment
		(start 396.422118 -165.363906)
		(end 396.422118 -164.724588)
		(width 0.3556)
		(layer "F.Cu")
		(net "GND")
	)
	(segment
		(start 23.946866 -7.215124)
		(end 23.946866 -8.320024)
		(width 0.3556)
		(layer "F.Cu")
		(net "GND")
	)
	(segment
		(start 359.110534 -228.45903)
		(end 359.110534 -228.99497)
		(width 0.2032)
		(layer "F.Cu")
		(net "GND")
	)
	(segment
		(start 300.022514 -208.366614)
		(end 301.343314 -208.366614)
		(width 0.381)
		(layer "F.Cu")
		(net "GND")
	)
	(segment
		(start 58.550302 -221.116652)
		(end 57.503314 -221.116652)
		(width 0.381)
		(layer "F.Cu")
		(net "GND")
	)
	(segment
		(start 375.55678 -220.041978)
		(end 375.557034 -220.041724)
		(width 0.254)
		(layer "F.Cu")
		(net "GND")
	)
	(segment
		(start 357.186992 -393.28725)
		(end 356.54996 -393.28725)
		(width 0.3556)
		(layer "F.Cu")
		(net "GND")
	)
	(segment
		(start 458.455014 -290.816792)
		(end 459.559914 -290.816792)
		(width 0.381)
		(layer "F.Cu")
		(net "GND")
	)
	(segment
		(start 184.439814 -224.516696)
		(end 185.544714 -224.516696)
		(width 0.381)
		(layer "F.Cu")
		(net "GND")
	)
	(segment
		(start 22.500082 -176.329086)
		(end 22.600666 -176.42967)
		(width 0.254)
		(layer "F.Cu")
		(net "GND")
	)
	(segment
		(start 260.180582 -249.166634)
		(end 259.075682 -249.166634)
		(width 0.381)
		(layer "F.Cu")
		(net "GND")
	)
	(segment
		(start 115.979448 -275.35886)
		(end 115.979194 -275.8948)
		(width 0.2032)
		(layer "F.Cu")
		(net "GND")
	)
	(segment
		(start 334.37703 -337.601306)
		(end 334.083406 -337.601306)
		(width 0.2032)
		(layer "F.Cu")
		(net "GND")
	)
	(segment
		(start 333.89824 -39.295324)
		(end 334.898746 -39.295324)
		(width 0.2032)
		(layer "F.Cu")
		(net "GND")
	)
	(segment
		(start 51.064414 -216.866724)
		(end 49.959514 -216.866724)
		(width 0.381)
		(layer "F.Cu")
		(net "GND")
	)
	(segment
		(start 54.42458 -145.1483)
		(end 54.878732 -144.694148)
		(width 0.2032)
		(layer "F.Cu")
		(net "GND")
	)
	(segment
		(start 49.959514 -196.466714)
		(end 51.064414 -196.466714)
		(width 0.381)
		(layer "F.Cu")
		(net "GND")
	)
	(segment
		(start 342.664034 -236.319568)
		(end 342.664034 -235.783882)
		(width 0.2032)
		(layer "F.Cu")
		(net "GND")
	)
	(segment
		(start 39.420546 -214.316564)
		(end 38.315646 -214.316564)
		(width 0.381)
		(layer "F.Cu")
		(net "GND")
	)
	(segment
		(start 162.913314 -316.316614)
		(end 164.018214 -316.316614)
		(width 0.381)
		(layer "F.Cu")
		(net "GND")
	)
	(segment
		(start 358.136952 -333.80426)
		(end 358.136952 -333.330804)
		(width 0.2032)
		(layer "F.Cu")
		(net "GND")
	)
	(segment
		(start 123.497848 -286.7533)
		(end 123.497848 -287.288986)
		(width 0.254)
		(layer "F.Cu")
		(net "GND")
	)
	(segment
		(start 309.122572 -42.916348)
		(end 308.506622 -42.916348)
		(width 0.381)
		(layer "F.Cu")
		(net "GND")
	)
	(segment
		(start 334.385412 -22.607778)
		(end 334.385412 -23.61438)
		(width 0.3556)
		(layer "F.Cu")
		(net "GND")
	)
	(segment
		(start 383.952496 -73.95845)
		(end 384.109976 -74.11593)
		(width 0.1778)
		(layer "F.Cu")
		(net "GND")
	)
	(segment
		(start 335.14538 -216.78646)
		(end 335.14538 -216.250774)
		(width 0.2032)
		(layer "F.Cu")
		(net "GND")
	)
	(segment
		(start 138.350244 -112.434624)
		(end 139.36218 -112.434624)
		(width 0.3556)
		(layer "F.Cu")
		(net "GND")
	)
	(segment
		(start 104.121712 -221.669864)
		(end 104.121712 -221.134178)
		(width 0.2032)
		(layer "F.Cu")
		(net "GND")
	)
	(segment
		(start 175.755554 -114.575336)
		(end 175.355504 -114.975386)
		(width 0.3556)
		(layer "F.Cu")
		(net "GND")
	)
	(segment
		(start 275.268182 -297.616626)
		(end 274.163282 -297.616626)
		(width 0.381)
		(layer "F.Cu")
		(net "GND")
	)
	(segment
		(start 358.280716 -270.475456)
		(end 358.280716 -271.011142)
		(width 0.254)
		(layer "F.Cu")
		(net "GND")
	)
	(segment
		(start 178.000914 -288.266632)
		(end 179.105814 -288.266632)
		(width 0.381)
		(layer "F.Cu")
		(net "GND")
	)
	(segment
		(start 126.207266 -233.87812)
		(end 126.207266 -233.34218)
		(width 0.2032)
		(layer "F.Cu")
		(net "GND")
	)
	(segment
		(start 184.439814 -301.01667)
		(end 185.544714 -301.01667)
		(width 0.381)
		(layer "F.Cu")
		(net "GND")
	)
	(segment
		(start 11.135614 -216.866724)
		(end 12.240514 -216.866724)
		(width 0.381)
		(layer "F.Cu")
		(net "GND")
	)
	(segment
		(start 459.559914 -195.616576)
		(end 458.455014 -195.616576)
		(width 0.381)
		(layer "F.Cu")
		(net "GND")
	)
	(segment
		(start 186.955684 -121.775474)
		(end 187.355734 -122.175524)
		(width 0.3556)
		(layer "F.Cu")
		(net "GND")
	)
	(segment
		(start 435.823614 -242.3668)
		(end 436.928514 -242.3668)
		(width 0.381)
		(layer "F.Cu")
		(net "GND")
	)
	(segment
		(start 345.553538 -45.949108)
		(end 345.15171 -46.350936)
		(width 0.2032)
		(layer "F.Cu")
		(net "GND")
	)
	(segment
		(start 301.343314 -229.616762)
		(end 302.448214 -229.616762)
		(width 0.381)
		(layer "F.Cu")
		(net "GND")
	)
	(segment
		(start 410.853382 -291.666676)
		(end 409.748482 -291.666676)
		(width 0.381)
		(layer "F.Cu")
		(net "GND")
	)
	(segment
		(start 406.753314 -204.96657)
		(end 408.161236 -204.96657)
		(width 0.381)
		(layer "F.Cu")
		(net "GND")
	)
	(segment
		(start 409.519882 -272.966688)
		(end 410.853382 -272.966688)
		(width 0.381)
		(layer "F.Cu")
		(net "GND")
	)
	(segment
		(start 13.345414 -200.716642)
		(end 12.240514 -200.716642)
		(width 0.381)
		(layer "F.Cu")
		(net "GND")
	)
	(segment
		(start 151.18588 -35.794188)
		(end 149.352 -35.794188)
		(width 0.3556)
		(layer "F.Cu")
		(net "GND")
	)
	(segment
		(start 278.711914 -296.766742)
		(end 279.816814 -296.766742)
		(width 0.381)
		(layer "F.Cu")
		(net "GND")
	)
	(segment
		(start 349.71228 -238.76127)
		(end 349.71228 -238.225584)
		(width 0.2032)
		(layer "F.Cu")
		(net "GND")
	)
	(segment
		(start 341.37727 -47.510446)
		(end 341.105998 -47.040546)
		(width 0.2032)
		(layer "F.Cu")
		(net "GND")
	)
	(segment
		(start 94.723712 -223.297496)
		(end 94.723712 -222.76181)
		(width 0.254)
		(layer "F.Cu")
		(net "GND")
	)
	(segment
		(start 328.244962 -39.946072)
		(end 328.434446 -39.756588)
		(width 0.2032)
		(layer "F.Cu")
		(net "GND")
	)
	(segment
		(start 214.615014 -230.466646)
		(end 215.719914 -230.466646)
		(width 0.381)
		(layer "F.Cu")
		(net "GND")
	)
	(segment
		(start 161.808414 -267.866622)
		(end 162.913314 -267.866622)
		(width 0.381)
		(layer "F.Cu")
		(net "GND")
	)
	(segment
		(start 125.847094 -271.289272)
		(end 125.847094 -271.825212)
		(width 0.2032)
		(layer "F.Cu")
		(net "GND")
	)
	(segment
		(start 208.176114 -314.616592)
		(end 209.281014 -314.616592)
		(width 0.381)
		(layer "F.Cu")
		(net "GND")
	)
	(segment
		(start 167.461946 -229.616762)
		(end 166.357046 -229.616762)
		(width 0.381)
		(layer "F.Cu")
		(net "GND")
	)
	(segment
		(start 207.071214 -196.466714)
		(end 208.176114 -196.466714)
		(width 0.381)
		(layer "F.Cu")
		(net "GND")
	)
	(segment
		(start 333.944214 -16.847312)
		(end 333.702152 -16.60525)
		(width 0.381)
		(layer "F.Cu")
		(net "GND")
	)
	(segment
		(start 92.844112 -239.57534)
		(end 92.844366 -239.575086)
		(width 0.2032)
		(layer "F.Cu")
		(net "GND")
	)
	(segment
		(start 375.666762 -272.917158)
		(end 375.667016 -273.453098)
		(width 0.2032)
		(layer "F.Cu")
		(net "GND")
	)
	(segment
		(start 381.126238 -366.265206)
		(end 381.750824 -365.64062)
		(width 0.508)
		(layer "F.Cu")
		(net "GND")
	)
	(segment
		(start 345.554554 -50.951384)
		(end 345.15171 -50.59172)
		(width 0.1778)
		(layer "F.Cu")
		(net "GND")
	)
	(segment
		(start 376.136916 -287.288986)
		(end 376.136662 -287.28924)
		(width 0.254)
		(layer "F.Cu")
		(net "GND")
	)
	(segment
		(start 378.956316 -287.288986)
		(end 378.956062 -287.28924)
		(width 0.254)
		(layer "F.Cu")
		(net "GND")
	)
	(segment
		(start 48.854614 -202.416664)
		(end 49.959514 -202.416664)
		(width 0.381)
		(layer "F.Cu")
		(net "GND")
	)
	(segment
		(start 457.0349 -49.476406)
		(end 457.949808 -49.476406)
		(width 0.508)
		(layer "F.Cu")
		(net "GND")
	)
	(segment
		(start 22.123146 -304.416714)
		(end 23.228046 -304.416714)
		(width 0.381)
		(layer "F.Cu")
		(net "GND")
	)
	(segment
		(start 188.988446 -258.516628)
		(end 187.883546 -258.516628)
		(width 0.381)
		(layer "F.Cu")
		(net "GND")
	)
	(segment
		(start 113.629694 -285.939484)
		(end 113.629694 -286.475424)
		(width 0.254)
		(layer "F.Cu")
		(net "GND")
	)
	(segment
		(start 391.006838 -27.68219)
		(end 391.006838 -27.109928)
		(width 0.3556)
		(layer "F.Cu")
		(net "GND")
	)
	(segment
		(start 335.784444 -59.75096)
		(end 335.899252 -59.636152)
		(width 0.2032)
		(layer "F.Cu")
		(net "GND")
	)
	(segment
		(start 277.607014 -244.916706)
		(end 278.711914 -244.916706)
		(width 0.381)
		(layer "F.Cu")
		(net "GND")
	)
	(segment
		(start 98.013266 -233.87812)
		(end 98.013266 -233.34218)
		(width 0.2032)
		(layer "F.Cu")
		(net "GND")
	)
	(segment
		(start 344.54338 -226.553268)
		(end 344.54338 -226.017582)
		(width 0.254)
		(layer "F.Cu")
		(net "GND")
	)
	(segment
		(start 345.48318 -216.78646)
		(end 345.48318 -216.250774)
		(width 0.254)
		(layer "F.Cu")
		(net "GND")
	)
	(segment
		(start 343.60358 -247.714262)
		(end 343.60358 -247.178576)
		(width 0.2032)
		(layer "F.Cu")
		(net "GND")
	)
	(segment
		(start 214.615014 -316.316614)
		(end 215.719914 -316.316614)
		(width 0.381)
		(layer "F.Cu")
		(net "GND")
	)
	(segment
		(start 113.519712 -220.041978)
		(end 113.519966 -220.041724)
		(width 0.254)
		(layer "F.Cu")
		(net "GND")
	)
	(segment
		(start 193.088514 -280.61666)
		(end 194.193414 -280.61666)
		(width 0.381)
		(layer "F.Cu")
		(net "GND")
	)
	(segment
		(start 418.397182 -210.066636)
		(end 417.072572 -210.066636)
		(width 0.381)
		(layer "F.Cu")
		(net "GND")
	)
	(segment
		(start 211.619846 -300.166786)
		(end 210.514946 -300.166786)
		(width 0.381)
		(layer "F.Cu")
		(net "GND")
	)
	(segment
		(start 277.607014 -201.56678)
		(end 278.711914 -201.56678)
		(width 0.381)
		(layer "F.Cu")
		(net "GND")
	)
	(segment
		(start 361.460034 -229.808532)
		(end 361.460034 -229.272846)
		(width 0.2032)
		(layer "F.Cu")
		(net "GND")
	)
	(segment
		(start 207.70215 -112.97285)
		(end 208.06029 -112.61471)
		(width 0.3556)
		(layer "F.Cu")
		(net "GND")
	)
	(segment
		(start 232.000044 -53.364892)
		(end 230.984044 -53.364892)
		(width 0.381)
		(layer "F.Cu")
		(net "GND")
	)
	(segment
		(start 126.787148 -270.167862)
		(end 126.787148 -270.19758)
		(width 0.2032)
		(layer "F.Cu")
		(net "GND")
	)
	(segment
		(start 57.503314 -312.91657)
		(end 58.824114 -312.91657)
		(width 0.381)
		(layer "F.Cu")
		(net "GND")
	)
	(segment
		(start 334.899508 -46.449996)
		(end 335.299558 -46.850046)
		(width 0.2032)
		(layer "F.Cu")
		(net "GND")
	)
	(segment
		(start 349.822516 -274.26666)
		(end 349.822262 -274.266914)
		(width 0.254)
		(layer "F.Cu")
		(net "GND")
	)
	(segment
		(start 441.028582 -284.866588)
		(end 442.133482 -284.866588)
		(width 0.381)
		(layer "F.Cu")
		(net "GND")
	)
	(segment
		(start 57.503314 -295.916604)
		(end 58.608214 -295.916604)
		(width 0.381)
		(layer "F.Cu")
		(net "GND")
	)
	(segment
		(start 49.959514 -210.066636)
		(end 51.064414 -210.066636)
		(width 0.381)
		(layer "F.Cu")
		(net "GND")
	)
	(segment
		(start 136.184894 -253.383796)
		(end 136.184894 -253.919736)
		(width 0.2032)
		(layer "F.Cu")
		(net "GND")
	)
	(segment
		(start 368.03838 -226.553268)
		(end 368.03838 -226.017582)
		(width 0.254)
		(layer "F.Cu")
		(net "GND")
	)
	(segment
		(start 374.61698 -228.1809)
		(end 374.617234 -228.180646)
		(width 0.2032)
		(layer "F.Cu")
		(net "GND")
	)
	(segment
		(start 215.719914 -210.066636)
		(end 216.824814 -210.066636)
		(width 0.381)
		(layer "F.Cu")
		(net "GND")
	)
	(segment
		(start 45.859446 -281.466798)
		(end 46.964346 -281.466798)
		(width 0.381)
		(layer "F.Cu")
		(net "GND")
	)
	(segment
		(start 428.279814 -197.316598)
		(end 429.384714 -197.316598)
		(width 0.381)
		(layer "F.Cu")
		(net "GND")
	)
	(segment
		(start 345.15171 -51.59248)
		(end 345.554554 -51.95189)
		(width 0.1778)
		(layer "F.Cu")
		(net "GND")
	)
	(segment
		(start 169.352214 -221.116652)
		(end 170.457114 -221.116652)
		(width 0.381)
		(layer "F.Cu")
		(net "GND")
	)
	(segment
		(start 46.697138 -334.537304)
		(end 46.697138 -335.477612)
		(width 0.508)
		(layer "F.Cu")
		(net "GND")
	)
	(segment
		(start 444.472314 -258.516628)
		(end 445.577214 -258.516628)
		(width 0.381)
		(layer "F.Cu")
		(net "GND")
	)
	(segment
		(start 56.182514 -314.616592)
		(end 57.503314 -314.616592)
		(width 0.381)
		(layer "F.Cu")
		(net "GND")
	)
	(segment
		(start 356.761034 -234.691936)
		(end 356.761034 -234.15625)
		(width 0.2032)
		(layer "F.Cu")
		(net "GND")
	)
	(segment
		(start 453.121014 -204.96657)
		(end 452.016114 -204.96657)
		(width 0.381)
		(layer "F.Cu")
		(net "GND")
	)
	(segment
		(start 405.648414 -208.366614)
		(end 406.753314 -208.366614)
		(width 0.381)
		(layer "F.Cu")
		(net "GND")
	)
	(segment
		(start 451.81774 -112.772698)
		(end 452.73468 -112.772698)
		(width 0.3556)
		(layer "F.Cu")
		(net "GND")
	)
	(segment
		(start 421.840914 -317.166752)
		(end 422.945814 -317.166752)
		(width 0.381)
		(layer "F.Cu")
		(net "GND")
	)
	(segment
		(start 109.870494 -277.800562)
		(end 109.870494 -278.336502)
		(width 0.254)
		(layer "F.Cu")
		(net "GND")
	)
	(segment
		(start 293.799514 -240.666778)
		(end 292.694614 -240.666778)
		(width 0.381)
		(layer "F.Cu")
		(net "GND")
	)
	(segment
		(start 117.53088 -102.809548)
		(end 117.604794 -102.883462)
		(width 0.3556)
		(layer "F.Cu")
		(net "GND")
	)
	(segment
		(start 159.828992 -110.990888)
		(end 159.91078 -110.9091)
		(width 0.3556)
		(layer "F.Cu")
		(net "GND")
	)
	(segment
		(start 405.648414 -278.066754)
		(end 406.753314 -278.066754)
		(width 0.381)
		(layer "F.Cu")
		(net "GND")
	)
	(segment
		(start 382.135634 -220.041978)
		(end 382.135634 -219.506038)
		(width 0.254)
		(layer "F.Cu")
		(net "GND")
	)
	(segment
		(start 294.904414 -267.016738)
		(end 293.799514 -267.016738)
		(width 0.381)
		(layer "F.Cu")
		(net "GND")
	)
	(segment
		(start 332.906116 -259.081016)
		(end 332.435962 -258.80314)
		(width 0.254)
		(layer "F.Cu")
		(net "GND")
	)
	(segment
		(start 42.415714 -245.76659)
		(end 41.310814 -245.76659)
		(width 0.381)
		(layer "F.Cu")
		(net "GND")
	)
	(segment
		(start 208.176114 -286.56661)
		(end 209.281014 -286.56661)
		(width 0.381)
		(layer "F.Cu")
		(net "GND")
	)
	(segment
		(start 405.539194 -285.716726)
		(end 406.753314 -285.716726)
		(width 0.381)
		(layer "F.Cu")
		(net "GND")
	)
	(segment
		(start 34.871914 -250.866656)
		(end 35.976814 -250.866656)
		(width 0.381)
		(layer "F.Cu")
		(net "GND")
	)
	(segment
		(start 173.900846 -289.11677)
		(end 175.005746 -289.11677)
		(width 0.381)
		(layer "F.Cu")
		(net "GND")
	)
	(segment
		(start 126.317248 -273.730974)
		(end 126.317248 -274.266914)
		(width 0.2032)
		(layer "F.Cu")
		(net "GND")
	)
	(segment
		(start 90.872056 -79.078836)
		(end 90.872056 -79.815436)
		(width 0.3556)
		(layer "F.Cu")
		(net "GND")
	)
	(segment
		(start 101.302312 -223.297496)
		(end 101.302312 -222.76181)
		(width 0.254)
		(layer "F.Cu")
		(net "GND")
	)
	(segment
		(start 154.792426 -64.761364)
		(end 154.106626 -64.761364)
		(width 0.3556)
		(layer "F.Cu")
		(net "GND")
	)
	(segment
		(start 444.472314 -229.616762)
		(end 445.577214 -229.616762)
		(width 0.381)
		(layer "F.Cu")
		(net "GND")
	)
	(segment
		(start 345.15171 -55.355236)
		(end 345.554554 -54.953408)
		(width 0.1778)
		(layer "F.Cu")
		(net "GND")
	)
	(segment
		(start 285.150814 -250.016772)
		(end 286.255714 -250.016772)
		(width 0.381)
		(layer "F.Cu")
		(net "GND")
	)
	(segment
		(start 92.844366 -228.180646)
		(end 92.844366 -227.64496)
		(width 0.2032)
		(layer "F.Cu")
		(net "GND")
	)
	(segment
		(start 198.10476 -114.498628)
		(end 193.09588 -114.498628)
		(width 0.3556)
		(layer "F.Cu")
		(net "GND")
	)
	(segment
		(start 244.4115 -247.051068)
		(end 242.12169 -247.051068)
		(width 0.3556)
		(layer "F.Cu")
		(net "GND")
	)
	(segment
		(start 379.896116 -276.986492)
		(end 379.895862 -277.522432)
		(width 0.2032)
		(layer "F.Cu")
		(net "GND")
	)
	(segment
		(start 346.063316 -284.033468)
		(end 346.063062 -284.033722)
		(width 0.254)
		(layer "F.Cu")
		(net "GND")
	)
	(segment
		(start 339.484462 -283.498036)
		(end 339.484462 -284.033722)
		(width 0.254)
		(layer "F.Cu")
		(net "GND")
	)
	(segment
		(start 279.80767 -425.69638)
		(end 280.410158 -425.69638)
		(width 0.3556)
		(layer "F.Cu")
		(net "GND")
	)
	(segment
		(start 123.967494 -255.547368)
		(end 123.967748 -255.547622)
		(width 0.2032)
		(layer "F.Cu")
		(net "GND")
	)
	(segment
		(start 354.88118 -220.041978)
		(end 354.881434 -220.041724)
		(width 0.254)
		(layer "F.Cu")
		(net "GND")
	)
	(segment
		(start 267.724382 -250.866656)
		(end 268.829282 -250.866656)
		(width 0.381)
		(layer "F.Cu")
		(net "GND")
	)
	(segment
		(start 386.474716 -254.197612)
		(end 387.417564 -254.197612)
		(width 0.2032)
		(layer "F.Cu")
		(net "GND")
	)
	(segment
		(start 182.549546 -315.46673)
		(end 181.444646 -315.46673)
		(width 0.381)
		(layer "F.Cu")
		(net "GND")
	)
	(segment
		(start 452.016114 -270.416782)
		(end 450.911214 -270.416782)
		(width 0.381)
		(layer "F.Cu")
		(net "GND")
	)
	(segment
		(start 115.039648 -264.499852)
		(end 115.039394 -264.500106)
		(width 0.254)
		(layer "F.Cu")
		(net "GND")
	)
	(segment
		(start 110.325154 -335.855056)
		(end 110.151926 -336.27314)
		(width 0.1778)
		(layer "F.Cu")
		(net "GND")
	)
	(segment
		(start 200.632314 -264.466578)
		(end 201.737214 -264.466578)
		(width 0.381)
		(layer "F.Cu")
		(net "GND")
	)
	(segment
		(start 172.795946 -311.216802)
		(end 173.900846 -311.216802)
		(width 0.381)
		(layer "F.Cu")
		(net "GND")
	)
	(segment
		(start 119.634 -54.02199)
		(end 120.777 -54.02199)
		(width 0.3556)
		(layer "F.Cu")
		(net "GND")
	)
	(segment
		(start 20.785582 -428.424086)
		(end 20.785582 -429.047148)
		(width 0.3556)
		(layer "F.Cu")
		(net "GND")
	)
	(segment
		(start 286.255714 -229.616762)
		(end 287.360614 -229.616762)
		(width 0.381)
		(layer "F.Cu")
		(net "GND")
	)
	(segment
		(start 236.7153 -248.757948)
		(end 236.7153 -247.744488)
		(width 0.3556)
		(layer "F.Cu")
		(net "GND")
	)
	(segment
		(start 436.928514 -301.866808)
		(end 438.033414 -301.866808)
		(width 0.381)
		(layer "F.Cu")
		(net "GND")
	)
	(segment
		(start 338.90458 -223.297496)
		(end 338.90458 -222.76181)
		(width 0.254)
		(layer "F.Cu")
		(net "GND")
	)
	(segment
		(start 122.66168 -101.10724)
		(end 123.360942 -100.407978)
		(width 0.254)
		(layer "F.Cu")
		(net "GND")
	)
	(segment
		(start 25.946608 -129.380996)
		(end 26.63825 -129.380996)
		(width 0.381)
		(layer "F.Cu")
		(net "GND")
	)
	(segment
		(start 358.280716 -259.616702)
		(end 358.280462 -259.616956)
		(width 0.254)
		(layer "F.Cu")
		(net "GND")
	)
	(segment
		(start 122.558048 -259.093462)
		(end 122.557794 -259.616956)
		(width 0.254)
		(layer "F.Cu")
		(net "GND")
	)
	(segment
		(start 86.265766 -246.08663)
		(end 86.265766 -245.55069)
		(width 0.2032)
		(layer "F.Cu")
		(net "GND")
	)
	(segment
		(start 94.254066 -228.99497)
		(end 94.253812 -228.994716)
		(width 0.2032)
		(layer "F.Cu")
		(net "GND")
	)
	(segment
		(start 378.846334 -220.855794)
		(end 378.846334 -220.319854)
		(width 0.2032)
		(layer "F.Cu")
		(net "GND")
	)
	(segment
		(start 462.555082 -261.066788)
		(end 463.659982 -261.066788)
		(width 0.381)
		(layer "F.Cu")
		(net "GND")
	)
	(segment
		(start 43.183556 -58.655712)
		(end 44.279058 -58.655712)
		(width 0.3556)
		(layer "F.Cu")
		(net "GND")
	)
	(segment
		(start 94.363794 -266.128246)
		(end 94.363794 -265.592306)
		(width 0.254)
		(layer "F.Cu")
		(net "GND")
	)
	(segment
		(start 57.503314 -271.266666)
		(end 58.608214 -271.266666)
		(width 0.381)
		(layer "F.Cu")
		(net "GND")
	)
	(segment
		(start 217.062558 -25.311354)
		(end 217.062558 -27.76347)
		(width 0.3556)
		(layer "F.Cu")
		(net "GND")
	)
	(segment
		(start 289.250882 -244.066568)
		(end 290.355782 -244.066568)
		(width 0.381)
		(layer "F.Cu")
		(net "GND")
	)
	(segment
		(start 97.073466 -230.622602)
		(end 97.073466 -230.086662)
		(width 0.2032)
		(layer "F.Cu")
		(net "GND")
	)
	(segment
		(start 460.664814 -238.966756)
		(end 459.559914 -238.966756)
		(width 0.381)
		(layer "F.Cu")
		(net "GND")
	)
	(segment
		(start 170.457114 -301.01667)
		(end 169.352214 -301.01667)
		(width 0.381)
		(layer "F.Cu")
		(net "GND")
	)
	(segment
		(start 266.619482 -224.516696)
		(end 267.724382 -224.516696)
		(width 0.381)
		(layer "F.Cu")
		(net "GND")
	)
	(segment
		(start 431.36693 -10.27303)
		(end 431.36693 -11.26998)
		(width 0.3556)
		(layer "F.Cu")
		(net "GND")
	)
	(segment
		(start 381.665734 -245.27256)
		(end 381.665734 -244.73662)
		(width 0.2032)
		(layer "F.Cu")
		(net "GND")
	)
	(segment
		(start 117.388894 -281.591766)
		(end 117.389148 -281.59202)
		(width 0.254)
		(layer "F.Cu")
		(net "GND")
	)
	(segment
		(start 200.632314 -204.116686)
		(end 201.737214 -204.116686)
		(width 0.381)
		(layer "F.Cu")
		(net "GND")
	)
	(segment
		(start 28.638246 -391.310876)
		(end 28.028646 -391.310876)
		(width 0.3556)
		(layer "F.Cu")
		(net "GND")
	)
	(segment
		(start 123.497848 -276.986492)
		(end 123.497594 -277.522432)
		(width 0.2032)
		(layer "F.Cu")
		(net "GND")
	)
	(segment
		(start 156.090874 -51.531012)
		(end 156.090874 -50.896012)
		(width 0.3556)
		(layer "F.Cu")
		(net "GND")
	)
	(segment
		(start 135.714994 -281.869896)
		(end 135.714994 -282.405836)
		(width 0.254)
		(layer "F.Cu")
		(net "GND")
	)
	(segment
		(start 162.913314 -215.166702)
		(end 161.808414 -215.166702)
		(width 0.381)
		(layer "F.Cu")
		(net "GND")
	)
	(segment
		(start 312.987182 -297.616626)
		(end 314.092082 -297.616626)
		(width 0.381)
		(layer "F.Cu")
		(net "GND")
	)
	(segment
		(start 347.472762 -264.778236)
		(end 347.472762 -265.313922)
		(width 0.2032)
		(layer "F.Cu")
		(net "GND")
	)
	(segment
		(start 376.026934 -227.367084)
		(end 376.026934 -226.831144)
		(width 0.2032)
		(layer "F.Cu")
		(net "GND")
	)
	(segment
		(start 333.679292 -339.52561)
		(end 333.20228 -340.002622)
		(width 0.2032)
		(layer "F.Cu")
		(net "GND")
	)
	(segment
		(start 59.842146 -195.616576)
		(end 60.947046 -195.616576)
		(width 0.381)
		(layer "F.Cu")
		(net "GND")
	)
	(segment
		(start 301.343314 -263.616694)
		(end 302.448214 -263.616694)
		(width 0.381)
		(layer "F.Cu")
		(net "GND")
	)
	(segment
		(start 300.022514 -276.366732)
		(end 301.343314 -276.366732)
		(width 0.381)
		(layer "F.Cu")
		(net "GND")
	)
	(segment
		(start 105.171494 -284.311598)
		(end 105.171494 -284.847538)
		(width 0.254)
		(layer "F.Cu")
		(net "GND")
	)
	(segment
		(start 453.121014 -272.116804)
		(end 452.016114 -272.116804)
		(width 0.381)
		(layer "F.Cu")
		(net "GND")
	)
	(segment
		(start 88.255094 -263.150604)
		(end 88.255094 -263.686544)
		(width 0.254)
		(layer "F.Cu")
		(net "GND")
	)
	(segment
		(start 30.771846 -298.466764)
		(end 31.876746 -298.466764)
		(width 0.381)
		(layer "F.Cu")
		(net "GND")
	)
	(segment
		(start 48.854614 -249.166634)
		(end 49.959514 -249.166634)
		(width 0.381)
		(layer "F.Cu")
		(net "GND")
	)
	(segment
		(start 33.767014 -211.766658)
		(end 34.871914 -211.766658)
		(width 0.381)
		(layer "F.Cu")
		(net "GND")
	)
	(segment
		(start 296.794682 -310.366664)
		(end 297.899582 -310.366664)
		(width 0.381)
		(layer "F.Cu")
		(net "GND")
	)
	(segment
		(start 171.562014 -198.166736)
		(end 170.457114 -198.166736)
		(width 0.381)
		(layer "F.Cu")
		(net "GND")
	)
	(segment
		(start 207.071214 -261.066788)
		(end 208.176114 -261.066788)
		(width 0.381)
		(layer "F.Cu")
		(net "GND")
	)
	(segment
		(start 99.986846 -103.343202)
		(end 99.286568 -103.343202)
		(width 0.3556)
		(layer "F.Cu")
		(net "GND")
	)
	(segment
		(start 369.448334 -224.111566)
		(end 369.448334 -223.575626)
		(width 0.2032)
		(layer "F.Cu")
		(net "GND")
	)
	(segment
		(start 330.897738 -37.096192)
		(end 330.896976 -37.63518)
		(width 0.2032)
		(layer "F.Cu")
		(net "GND")
	)
	(segment
		(start 202.971146 -298.466764)
		(end 204.076046 -298.466764)
		(width 0.381)
		(layer "F.Cu")
		(net "GND")
	)
	(segment
		(start 196.532246 -300.166786)
		(end 195.427346 -300.166786)
		(width 0.381)
		(layer "F.Cu")
		(net "GND")
	)
	(segment
		(start 124.437648 -273.730974)
		(end 124.437648 -274.26666)
		(width 0.254)
		(layer "F.Cu")
		(net "GND")
	)
	(segment
		(start 312.987182 -278.916638)
		(end 314.092082 -278.916638)
		(width 0.381)
		(layer "F.Cu")
		(net "GND")
	)
	(segment
		(start 345.953334 -242.017042)
		(end 345.95308 -242.016788)
		(width 0.2032)
		(layer "F.Cu")
		(net "GND")
	)
	(segment
		(start 452.016114 -315.46673)
		(end 450.911214 -315.46673)
		(width 0.381)
		(layer "F.Cu")
		(net "GND")
	)
	(segment
		(start 346.532962 -255.011682)
		(end 346.532962 -255.547622)
		(width 0.2032)
		(layer "F.Cu")
		(net "GND")
	)
	(segment
		(start 169.624248 -355.379274)
		(end 169.31894 -355.379274)
		(width 0.2032)
		(layer "F.Cu")
		(net "GND")
	)
	(segment
		(start 196.229478 -79.057246)
		(end 194.746372 -79.057246)
		(width 0.3556)
		(layer "F.Cu")
		(net "GND")
	)
	(segment
		(start 327.129902 -22.261576)
		(end 328.110342 -22.261576)
		(width 0.3556)
		(layer "F.Cu")
		(net "GND")
	)
	(segment
		(start 204.076046 -290.816792)
		(end 205.180946 -290.816792)
		(width 0.381)
		(layer "F.Cu")
		(net "GND")
	)
	(segment
		(start 407.858214 -225.36658)
		(end 406.753314 -225.36658)
		(width 0.381)
		(layer "F.Cu")
		(net "GND")
	)
	(segment
		(start 456.116182 -202.416664)
		(end 455.011282 -202.416664)
		(width 0.381)
		(layer "F.Cu")
		(net "GND")
	)
	(segment
		(start 42.057066 -11.26998)
		(end 42.057066 -12.37488)
		(width 0.3556)
		(layer "F.Cu")
		(net "GND")
	)
	(segment
		(start 344.073734 -246.900446)
		(end 344.07348 -246.900192)
		(width 0.2032)
		(layer "F.Cu")
		(net "GND")
	)
	(segment
		(start 26.223214 -286.56661)
		(end 27.328114 -286.56661)
		(width 0.381)
		(layer "F.Cu")
		(net "GND")
	)
	(segment
		(start 210.514946 -251.716794)
		(end 211.619846 -251.716794)
		(width 0.381)
		(layer "F.Cu")
		(net "GND")
	)
	(segment
		(start 96.133666 -246.900446)
		(end 96.133412 -246.900192)
		(width 0.2032)
		(layer "F.Cu")
		(net "GND")
	)
	(segment
		(start 44.754546 -201.56678)
		(end 45.859446 -201.56678)
		(width 0.381)
		(layer "F.Cu")
		(net "GND")
	)
	(segment
		(start 188.988446 -273.816572)
		(end 190.093346 -273.816572)
		(width 0.381)
		(layer "F.Cu")
		(net "GND")
	)
	(segment
		(start 340.894162 -271.289272)
		(end 340.894416 -271.289526)
		(width 0.2032)
		(layer "F.Cu")
		(net "GND")
	)
	(segment
		(start 300.022514 -311.216802)
		(end 301.343314 -311.216802)
		(width 0.381)
		(layer "F.Cu")
		(net "GND")
	)
	(segment
		(start 107.521248 -280.242264)
		(end 107.521248 -280.77795)
		(width 0.254)
		(layer "F.Cu")
		(net "GND")
	)
	(segment
		(start 356.21595 -417.159948)
		(end 355.6 -417.159948)
		(width 0.3556)
		(layer "F.Cu")
		(net "GND")
	)
	(segment
		(start 193.02476 -111.310928)
		(end 193.2178 -111.117888)
		(width 0.3556)
		(layer "F.Cu")
		(net "GND")
	)
	(segment
		(start 372.847362 -277.800562)
		(end 372.847362 -278.336248)
		(width 0.254)
		(layer "F.Cu")
		(net "GND")
	)
	(segment
		(start 35.976814 -267.866622)
		(end 34.871914 -267.866622)
		(width 0.381)
		(layer "F.Cu")
		(net "GND")
	)
	(segment
		(start 341.254334 -224.111566)
		(end 341.254334 -223.575626)
		(width 0.2032)
		(layer "F.Cu")
		(net "GND")
	)
	(segment
		(start 282.811982 -299.316648)
		(end 283.916882 -299.316648)
		(width 0.381)
		(layer "F.Cu")
		(net "GND")
	)
	(segment
		(start 419.502082 -286.56661)
		(end 418.397182 -286.56661)
		(width 0.381)
		(layer "F.Cu")
		(net "GND")
	)
	(segment
		(start 335.899252 -57.605168)
		(end 335.899252 -58.43524)
		(width 0.254)
		(layer "F.Cu")
		(net "GND")
	)
	(segment
		(start 349.822516 -280.242264)
		(end 349.822516 -280.77795)
		(width 0.2032)
		(layer "F.Cu")
		(net "GND")
	)
	(segment
		(start 333.155544 -18.397474)
		(end 333.155798 -18.39722)
		(width 0.3556)
		(layer "F.Cu")
		(net "GND")
	)
	(segment
		(start 342.194134 -243.644928)
		(end 342.19388 -243.644674)
		(width 0.2032)
		(layer "F.Cu")
		(net "GND")
	)
	(segment
		(start 305.92268 -49.621948)
		(end 306.74183 -49.621948)
		(width 0.3556)
		(layer "F.Cu")
		(net "GND")
	)
	(segment
		(start 382.245362 -277.800562)
		(end 382.245362 -278.336502)
		(width 0.2032)
		(layer "F.Cu")
		(net "GND")
	)
	(segment
		(start 380.25578 -239.57534)
		(end 380.256034 -239.575086)
		(width 0.2032)
		(layer "F.Cu")
		(net "GND")
	)
	(segment
		(start 5.99186 -101.166168)
		(end 7.454646 -101.166168)
		(width 0.3556)
		(layer "F.Cu")
		(net "GND")
	)
	(segment
		(start 90.964512 -241.203226)
		(end 90.964512 -240.667286)
		(width 0.2032)
		(layer "F.Cu")
		(net "GND")
	)
	(segment
		(start 29.22524 -139.066524)
		(end 29.22524 -138.378438)
		(width 0.3556)
		(layer "F.Cu")
		(net "GND")
	)
	(segment
		(start 65.047114 -271.266666)
		(end 66.367914 -271.266666)
		(width 0.381)
		(layer "F.Cu")
		(net "GND")
	)
	(segment
		(start 456.116182 -247.466612)
		(end 455.011282 -247.466612)
		(width 0.381)
		(layer "F.Cu")
		(net "GND")
	)
	(segment
		(start 405.648414 -244.916706)
		(end 406.753314 -244.916706)
		(width 0.381)
		(layer "F.Cu")
		(net "GND")
	)
	(segment
		(start 157.708346 -279.766776)
		(end 158.813246 -279.766776)
		(width 0.381)
		(layer "F.Cu")
		(net "GND")
	)
	(segment
		(start 60.947046 -306.116736)
		(end 62.051946 -306.116736)
		(width 0.381)
		(layer "F.Cu")
		(net "GND")
	)
	(segment
		(start 448.572382 -299.316648)
		(end 447.467482 -299.316648)
		(width 0.381)
		(layer "F.Cu")
		(net "GND")
	)
	(segment
		(start 340.894416 -268.034008)
		(end 340.894416 -268.569694)
		(width 0.2032)
		(layer "F.Cu")
		(net "GND")
	)
	(segment
		(start 49.959514 -297.616626)
		(end 51.064414 -297.616626)
		(width 0.381)
		(layer "F.Cu")
		(net "GND")
	)
	(segment
		(start 461.993996 -107.043728)
		(end 461.993996 -107.678728)
		(width 0.3556)
		(layer "F.Cu")
		(net "GND")
	)
	(segment
		(start 160.217358 -238.966756)
		(end 158.813246 -238.966756)
		(width 0.381)
		(layer "F.Cu")
		(net "GND")
	)
	(segment
		(start 412.989014 -276.366732)
		(end 414.297114 -276.366732)
		(width 0.381)
		(layer "F.Cu")
		(net "GND")
	)
	(segment
		(start 135.605266 -220.855794)
		(end 135.605266 -220.319854)
		(width 0.2032)
		(layer "F.Cu")
		(net "GND")
	)
	(segment
		(start 57.503314 -241.516662)
		(end 58.608214 -241.516662)
		(width 0.381)
		(layer "F.Cu")
		(net "GND")
	)
	(segment
		(start 448.572382 -250.866656)
		(end 447.467482 -250.866656)
		(width 0.381)
		(layer "F.Cu")
		(net "GND")
	)
	(segment
		(start 296.794682 -264.466578)
		(end 297.899582 -264.466578)
		(width 0.381)
		(layer "F.Cu")
		(net "GND")
	)
	(segment
		(start 285.150814 -195.616576)
		(end 286.255714 -195.616576)
		(width 0.381)
		(layer "F.Cu")
		(net "GND")
	)
	(segment
		(start 282.811982 -264.466578)
		(end 283.916882 -264.466578)
		(width 0.381)
		(layer "F.Cu")
		(net "GND")
	)
	(segment
		(start 11.135614 -249.166634)
		(end 12.240514 -249.166634)
		(width 0.381)
		(layer "F.Cu")
		(net "GND")
	)
	(segment
		(start 7.035546 -231.316784)
		(end 8.140446 -231.316784)
		(width 0.381)
		(layer "F.Cu")
		(net "GND")
	)
	(segment
		(start 23.228046 -220.266768)
		(end 24.332946 -220.266768)
		(width 0.381)
		(layer "F.Cu")
		(net "GND")
	)
	(segment
		(start 267.724382 -224.516696)
		(end 268.829282 -224.516696)
		(width 0.381)
		(layer "F.Cu")
		(net "GND")
	)
	(segment
		(start 372.377716 -254.197612)
		(end 372.377716 -254.733552)
		(width 0.2032)
		(layer "F.Cu")
		(net "GND")
	)
	(segment
		(start 121.148094 -281.591512)
		(end 121.148348 -281.591766)
		(width 0.254)
		(layer "F.Cu")
		(net "GND")
	)
	(segment
		(start 53.403246 -220.266768)
		(end 52.082446 -220.266768)
		(width 0.381)
		(layer "F.Cu")
		(net "GND")
	)
	(segment
		(start 175.005746 -227.066602)
		(end 173.900846 -227.066602)
		(width 0.381)
		(layer "F.Cu")
		(net "GND")
	)
	(segment
		(start 345.95308 -237.133638)
		(end 345.95308 -236.597952)
		(width 0.2032)
		(layer "F.Cu")
		(net "GND")
	)
	(segment
		(start 110.230666 -236.597952)
		(end 110.23092 -236.597698)
		(width 0.254)
		(layer "F.Cu")
		(net "GND")
	)
	(segment
		(start 305.443382 -314.616592)
		(end 306.764182 -314.616592)
		(width 0.381)
		(layer "F.Cu")
		(net "GND")
	)
	(segment
		(start 361.45978 -246.08663)
		(end 361.460034 -245.55069)
		(width 0.254)
		(layer "F.Cu")
		(net "GND")
	)
	(segment
		(start 86.265766 -228.1809)
		(end 86.265766 -227.64496)
		(width 0.2032)
		(layer "F.Cu")
		(net "GND")
	)
	(segment
		(start 87.785194 -288.381186)
		(end 87.785194 -288.917126)
		(width 0.2032)
		(layer "F.Cu")
		(net "GND")
	)
	(segment
		(start 90.605102 -281.87015)
		(end 90.604848 -282.405836)
		(width 0.254)
		(layer "F.Cu")
		(net "GND")
	)
	(segment
		(start 36.988496 -100.80879)
		(end 35.807396 -100.80879)
		(width 0.3556)
		(layer "F.Cu")
		(net "GND")
	)
	(segment
		(start 52.298346 -195.616576)
		(end 53.403246 -195.616576)
		(width 0.381)
		(layer "F.Cu")
		(net "GND")
	)
	(segment
		(start 85.325712 -228.1809)
		(end 85.325712 -227.64496)
		(width 0.2032)
		(layer "F.Cu")
		(net "GND")
	)
	(segment
		(start 374.726962 -274.54479)
		(end 374.726962 -275.08073)
		(width 0.2032)
		(layer "F.Cu")
		(net "GND")
	)
	(segment
		(start 428.279814 -285.716726)
		(end 429.384714 -285.716726)
		(width 0.381)
		(layer "F.Cu")
		(net "GND")
	)
	(segment
		(start 338.434934 -235.506006)
		(end 338.434934 -234.970066)
		(width 0.2032)
		(layer "F.Cu")
		(net "GND")
	)
	(segment
		(start 111.170466 -218.692476)
		(end 111.17072 -218.692222)
		(width 0.2032)
		(layer "F.Cu")
		(net "GND")
	)
	(segment
		(start 208.176114 -280.61666)
		(end 209.281014 -280.61666)
		(width 0.381)
		(layer "F.Cu")
		(net "GND")
	)
	(segment
		(start 123.387866 -217.600276)
		(end 123.387866 -217.064336)
		(width 0.254)
		(layer "F.Cu")
		(net "GND")
	)
	(segment
		(start 23.228046 -227.066602)
		(end 22.123146 -227.066602)
		(width 0.381)
		(layer "F.Cu")
		(net "GND")
	)
	(segment
		(start 173.900846 -307.816758)
		(end 175.005746 -307.816758)
		(width 0.381)
		(layer "F.Cu")
		(net "GND")
	)
	(segment
		(start 212.724746 -296.766742)
		(end 211.619846 -296.766742)
		(width 0.381)
		(layer "F.Cu")
		(net "GND")
	)
	(segment
		(start 343.133934 -245.27256)
		(end 343.13368 -245.272306)
		(width 0.2032)
		(layer "F.Cu")
		(net "GND")
	)
	(segment
		(start 106.001312 -226.017582)
		(end 106.001566 -226.017328)
		(width 0.254)
		(layer "F.Cu")
		(net "GND")
	)
	(segment
		(start 39.420546 -195.616576)
		(end 38.315646 -195.616576)
		(width 0.381)
		(layer "F.Cu")
		(net "GND")
	)
	(segment
		(start 188.988446 -233.016806)
		(end 187.883546 -233.016806)
		(width 0.381)
		(layer "F.Cu")
		(net "GND")
	)
	(segment
		(start 355.461316 -265.592306)
		(end 355.461316 -266.127992)
		(width 0.2032)
		(layer "F.Cu")
		(net "GND")
	)
	(segment
		(start 368.03838 -216.250774)
		(end 368.038634 -216.25052)
		(width 0.254)
		(layer "F.Cu")
		(net "GND")
	)
	(segment
		(start 303.5554 -55.133748)
		(end 303.634902 -55.054246)
		(width 0.508)
		(layer "F.Cu")
		(net "GND")
	)
	(segment
		(start 123.3043 -417.383468)
		(end 120.77827 -417.383468)
		(width 0.3556)
		(layer "F.Cu")
		(net "GND")
	)
	(segment
		(start 99.422712 -237.947454)
		(end 99.422966 -237.947454)
		(width 0.254)
		(layer "F.Cu")
		(net "GND")
	)
	(segment
		(start 460.664814 -199.01662)
		(end 459.559914 -199.01662)
		(width 0.381)
		(layer "F.Cu")
		(net "GND")
	)
	(segment
		(start 85.905594 -280.242264)
		(end 85.905594 -280.778204)
		(width 0.2032)
		(layer "F.Cu")
		(net "GND")
	)
	(segment
		(start 129.026666 -242.017042)
		(end 129.026666 -241.481102)
		(width 0.2032)
		(layer "F.Cu")
		(net "GND")
	)
	(segment
		(start 377.076716 -265.592306)
		(end 377.076716 -266.127992)
		(width 0.254)
		(layer "F.Cu")
		(net "GND")
	)
	(segment
		(start 204.076046 -225.36658)
		(end 205.180946 -225.36658)
		(width 0.381)
		(layer "F.Cu")
		(net "GND")
	)
	(segment
		(start 457.7461 -380.221236)
		(end 457.7461 -380.84887)
		(width 0.3556)
		(layer "F.Cu")
		(net "GND")
	)
	(segment
		(start 162.913314 -286.56661)
		(end 161.935414 -286.56661)
		(width 0.381)
		(layer "F.Cu")
		(net "GND")
	)
	(segment
		(start 344.073734 -250.155964)
		(end 344.07348 -250.15571)
		(width 0.2032)
		(layer "F.Cu")
		(net "GND")
	)
	(segment
		(start 137.484866 -232.250488)
		(end 136.545066 -231.714548)
		(width 0.254)
		(layer "F.Cu")
		(net "GND")
	)
	(segment
		(start 120.678448 -270.475456)
		(end 120.678194 -271.011396)
		(width 0.2032)
		(layer "F.Cu")
		(net "GND")
	)
	(segment
		(start 312.987182 -222.816674)
		(end 314.092082 -222.816674)
		(width 0.381)
		(layer "F.Cu")
		(net "GND")
	)
	(segment
		(start 334.205834 -241.203226)
		(end 334.675734 -241.481102)
		(width 0.254)
		(layer "F.Cu")
		(net "GND")
	)
	(segment
		(start 96.17583 -56.225948)
		(end 95.56623 -56.225948)
		(width 0.3556)
		(layer "F.Cu")
		(net "GND")
	)
	(segment
		(start 44.754546 -267.016738)
		(end 45.859446 -267.016738)
		(width 0.381)
		(layer "F.Cu")
		(net "GND")
	)
	(segment
		(start 11.135614 -213.46668)
		(end 12.240514 -213.46668)
		(width 0.381)
		(layer "F.Cu")
		(net "GND")
	)
	(segment
		(start 176.555654 -112.175544)
		(end 176.155604 -111.775494)
		(width 0.3556)
		(layer "F.Cu")
		(net "GND")
	)
	(segment
		(start 29.666946 -242.3668)
		(end 30.771846 -242.3668)
		(width 0.381)
		(layer "F.Cu")
		(net "GND")
	)
	(segment
		(start 89.554812 -233.877866)
		(end 89.554812 -233.34218)
		(width 0.2032)
		(layer "F.Cu")
		(net "GND")
	)
	(segment
		(start 447.157602 -17.433798)
		(end 446.548002 -17.433798)
		(width 0.4572)
		(layer "F.Cu")
		(net "GND")
	)
	(segment
		(start 113.629694 -255.011682)
		(end 113.629694 -255.547622)
		(width 0.254)
		(layer "F.Cu")
		(net "GND")
	)
	(segment
		(start 275.268182 -196.466714)
		(end 274.163282 -196.466714)
		(width 0.381)
		(layer "F.Cu")
		(net "GND")
	)
	(segment
		(start 98.592894 -269.66164)
		(end 98.592894 -270.19758)
		(width 0.2032)
		(layer "F.Cu")
		(net "GND")
	)
	(segment
		(start 104.591866 -227.367084)
		(end 104.591866 -226.831144)
		(width 0.254)
		(layer "F.Cu")
		(net "GND")
	)
	(segment
		(start 103.519478 -421.24884)
		(end 104.3178 -421.24884)
		(width 0.3556)
		(layer "F.Cu")
		(net "GND")
	)
	(segment
		(start 49.959514 -295.916604)
		(end 51.064414 -295.916604)
		(width 0.381)
		(layer "F.Cu")
		(net "GND")
	)
	(segment
		(start 378.84608 -246.900192)
		(end 378.84608 -246.364506)
		(width 0.2032)
		(layer "F.Cu")
		(net "GND")
	)
	(segment
		(start 124.327666 -230.622602)
		(end 124.327666 -230.086916)
		(width 0.2032)
		(layer "F.Cu")
		(net "GND")
	)
	(segment
		(start 56.182514 -272.966688)
		(end 57.503314 -272.966688)
		(width 0.381)
		(layer "F.Cu")
		(net "GND")
	)
	(segment
		(start 214.615014 -297.616626)
		(end 215.719914 -297.616626)
		(width 0.381)
		(layer "F.Cu")
		(net "GND")
	)
	(segment
		(start 204.076046 -240.666778)
		(end 205.180946 -240.666778)
		(width 0.381)
		(layer "F.Cu")
		(net "GND")
	)
	(segment
		(start 119.738648 -265.592306)
		(end 119.738648 -266.127992)
		(width 0.254)
		(layer "F.Cu")
		(net "GND")
	)
	(segment
		(start 293.799514 -268.71676)
		(end 292.694614 -268.71676)
		(width 0.381)
		(layer "F.Cu")
		(net "GND")
	)
	(segment
		(start 101.412294 -276.172676)
		(end 101.412294 -276.708362)
		(width 0.254)
		(layer "F.Cu")
		(net "GND")
	)
	(segment
		(start 380.25578 -216.78646)
		(end 380.25578 -216.250774)
		(width 0.254)
		(layer "F.Cu")
		(net "GND")
	)
	(segment
		(start 124.907294 -289.195002)
		(end 124.907294 -289.807142)
		(width 0.2032)
		(layer "F.Cu")
		(net "GND")
	)
	(segment
		(start 419.502082 -241.516662)
		(end 418.397182 -241.516662)
		(width 0.381)
		(layer "F.Cu")
		(net "GND")
	)
	(segment
		(start 15.684246 -296.766742)
		(end 16.789146 -296.766742)
		(width 0.381)
		(layer "F.Cu")
		(net "GND")
	)
	(segment
		(start 427.230032 -381.868934)
		(end 426.595032 -381.868934)
		(width 0.3556)
		(layer "F.Cu")
		(net "GND")
	)
	(segment
		(start 449.677282 -241.516662)
		(end 448.572382 -241.516662)
		(width 0.381)
		(layer "F.Cu")
		(net "GND")
	)
	(segment
		(start 166.357046 -244.916706)
		(end 167.461946 -244.916706)
		(width 0.381)
		(layer "F.Cu")
		(net "GND")
	)
	(segment
		(start 459.559914 -263.616694)
		(end 458.455014 -263.616694)
		(width 0.381)
		(layer "F.Cu")
		(net "GND")
	)
	(segment
		(start 456.116182 -211.766658)
		(end 457.221082 -211.766658)
		(width 0.381)
		(layer "F.Cu")
		(net "GND")
	)
	(segment
		(start 352.06178 -221.669864)
		(end 352.06178 -221.134178)
		(width 0.254)
		(layer "F.Cu")
		(net "GND")
	)
	(segment
		(start 23.228046 -292.516814)
		(end 24.332946 -292.516814)
		(width 0.381)
		(layer "F.Cu")
		(net "GND")
	)
	(segment
		(start 7.035546 -244.916706)
		(end 8.140446 -244.916706)
		(width 0.381)
		(layer "F.Cu")
		(net "GND")
	)
	(segment
		(start 220.487494 -100.23348)
		(end 221.1578 -100.23348)
		(width 0.3556)
		(layer "F.Cu")
		(net "GND")
	)
	(segment
		(start 212.724746 -231.316784)
		(end 211.619846 -231.316784)
		(width 0.381)
		(layer "F.Cu")
		(net "GND")
	)
	(segment
		(start 357.6955 -407.233628)
		(end 358.41178 -407.233628)
		(width 0.3556)
		(layer "F.Cu")
		(net "GND")
	)
	(segment
		(start 358.280716 -286.7533)
		(end 358.280716 -287.288986)
		(width 0.254)
		(layer "F.Cu")
		(net "GND")
	)
	(segment
		(start 337.96478 -222.76181)
		(end 337.965034 -222.761556)
		(width 0.254)
		(layer "F.Cu")
		(net "GND")
	)
	(segment
		(start 63.942214 -261.066788)
		(end 65.047114 -261.066788)
		(width 0.381)
		(layer "F.Cu")
		(net "GND")
	)
	(segment
		(start 39.420546 -292.516814)
		(end 38.315646 -292.516814)
		(width 0.381)
		(layer "F.Cu")
		(net "GND")
	)
	(segment
		(start 181.80812 -410.80817)
		(end 181.80812 -410.10586)
		(width 0.3556)
		(layer "F.Cu")
		(net "GND")
	)
	(segment
		(start 211.619846 -304.416714)
		(end 210.514946 -304.416714)
		(width 0.381)
		(layer "F.Cu")
		(net "GND")
	)
	(segment
		(start 370.498116 -279.150064)
		(end 370.497862 -279.150318)
		(width 0.254)
		(layer "F.Cu")
		(net "GND")
	)
	(segment
		(start 298.62018 -49.320196)
		(end 297.95851 -49.320196)
		(width 0.3556)
		(layer "F.Cu")
		(net "GND")
	)
	(segment
		(start 457.0349 -48.561498)
		(end 457.0349 -49.476406)
		(width 0.508)
		(layer "F.Cu")
		(net "GND")
	)
	(segment
		(start 281.707082 -250.866656)
		(end 282.811982 -250.866656)
		(width 0.381)
		(layer "F.Cu")
		(net "GND")
	)
	(segment
		(start 26.223214 -244.066568)
		(end 27.328114 -244.066568)
		(width 0.381)
		(layer "F.Cu")
		(net "GND")
	)
	(segment
		(start 297.899582 -264.466578)
		(end 299.004482 -264.466578)
		(width 0.381)
		(layer "F.Cu")
		(net "GND")
	)
	(segment
		(start 335.725262 -288.381186)
		(end 335.725262 -288.916872)
		(width 0.254)
		(layer "F.Cu")
		(net "GND")
	)
	(segment
		(start 261.285482 -249.166634)
		(end 260.180582 -249.166634)
		(width 0.381)
		(layer "F.Cu")
		(net "GND")
	)
	(segment
		(start 349.712534 -235.506006)
		(end 349.71228 -234.970066)
		(width 0.2032)
		(layer "F.Cu")
		(net "GND")
	)
	(segment
		(start 420.736014 -203.266802)
		(end 421.840914 -203.266802)
		(width 0.381)
		(layer "F.Cu")
		(net "GND")
	)
	(segment
		(start 294.904414 -244.916706)
		(end 293.799514 -244.916706)
		(width 0.381)
		(layer "F.Cu")
		(net "GND")
	)
	(segment
		(start 180.339746 -227.066602)
		(end 181.444646 -227.066602)
		(width 0.381)
		(layer "F.Cu")
		(net "GND")
	)
	(segment
		(start 43.520614 -258.516628)
		(end 42.415714 -258.516628)
		(width 0.381)
		(layer "F.Cu")
		(net "GND")
	)
	(segment
		(start 120.678448 -263.96442)
		(end 120.678448 -264.499852)
		(width 0.2032)
		(layer "F.Cu")
		(net "GND")
	)
	(segment
		(start 182.549546 -307.816758)
		(end 181.444646 -307.816758)
		(width 0.381)
		(layer "F.Cu")
		(net "GND")
	)
	(segment
		(start 385.424934 -235.506006)
		(end 384.955034 -235.783882)
		(width 0.254)
		(layer "F.Cu")
		(net "GND")
	)
	(segment
		(start 275.268182 -211.766658)
		(end 274.163282 -211.766658)
		(width 0.381)
		(layer "F.Cu")
		(net "GND")
	)
	(segment
		(start 186.649614 -291.666676)
		(end 185.544714 -291.666676)
		(width 0.381)
		(layer "F.Cu")
		(net "GND")
	)
	(segment
		(start 352.06178 -216.78646)
		(end 352.06178 -216.250774)
		(width 0.254)
		(layer "F.Cu")
		(net "GND")
	)
	(segment
		(start 308.887114 -197.316598)
		(end 309.992014 -197.316598)
		(width 0.381)
		(layer "F.Cu")
		(net "GND")
	)
	(segment
		(start 441.028582 -204.116686)
		(end 442.133482 -204.116686)
		(width 0.381)
		(layer "F.Cu")
		(net "GND")
	)
	(segment
		(start 182.549546 -290.816792)
		(end 181.444646 -290.816792)
		(width 0.381)
		(layer "F.Cu")
		(net "GND")
	)
	(segment
		(start 121.508012 -240.388902)
		(end 121.508266 -240.389156)
		(width 0.2032)
		(layer "F.Cu")
		(net "GND")
	)
	(segment
		(start 7.035546 -313.766708)
		(end 8.140446 -313.766708)
		(width 0.381)
		(layer "F.Cu")
		(net "GND")
	)
	(segment
		(start 176.896014 -286.56661)
		(end 178.000914 -286.56661)
		(width 0.381)
		(layer "F.Cu")
		(net "GND")
	)
	(segment
		(start 383.184908 -260.430518)
		(end 383.185162 -260.430772)
		(width 0.254)
		(layer "F.Cu")
		(net "GND")
	)
	(segment
		(start 33.767014 -314.616592)
		(end 34.871914 -314.616592)
		(width 0.381)
		(layer "F.Cu")
		(net "GND")
	)
	(segment
		(start 117.279166 -234.691936)
		(end 117.279166 -234.15625)
		(width 0.254)
		(layer "F.Cu")
		(net "GND")
	)
	(segment
		(start 72.662034 -12.37488)
		(end 72.662034 -11.26998)
		(width 0.3556)
		(layer "F.Cu")
		(net "GND")
	)
	(segment
		(start 385.19608 -260.630162)
		(end 384.788156 -260.38937)
		(width 0.088646)
		(layer "F.Cu")
		(net "GND")
	)
	(segment
		(start 135.714994 -273.730974)
		(end 135.714994 -274.266914)
		(width 0.254)
		(layer "F.Cu")
		(net "GND")
	)
	(segment
		(start 48.854614 -288.266632)
		(end 49.959514 -288.266632)
		(width 0.381)
		(layer "F.Cu")
		(net "GND")
	)
	(segment
		(start 267.724382 -202.416664)
		(end 268.829282 -202.416664)
		(width 0.381)
		(layer "F.Cu")
		(net "GND")
	)
	(segment
		(start 45.859446 -244.916706)
		(end 46.964346 -244.916706)
		(width 0.381)
		(layer "F.Cu")
		(net "GND")
	)
	(segment
		(start 348.882716 -278.614378)
		(end 348.882716 -279.150318)
		(width 0.2032)
		(layer "F.Cu")
		(net "GND")
	)
	(segment
		(start 148.30425 -41.838118)
		(end 147.61845 -41.838118)
		(width 0.3556)
		(layer "F.Cu")
		(net "GND")
	)
	(segment
		(start 116.918994 -264.500106)
		(end 116.918994 -264.50036)
		(width 0.2032)
		(layer "F.Cu")
		(net "GND")
	)
	(segment
		(start 125.737112 -244.458744)
		(end 125.737366 -244.45849)
		(width 0.2032)
		(layer "F.Cu")
		(net "GND")
	)
	(segment
		(start 65.047114 -232.166668)
		(end 66.152014 -232.166668)
		(width 0.381)
		(layer "F.Cu")
		(net "GND")
	)
	(segment
		(start 350.762316 -281.869896)
		(end 350.762316 -282.405836)
		(width 0.2032)
		(layer "F.Cu")
		(net "GND")
	)
	(segment
		(start 432.379882 -213.46668)
		(end 433.484782 -213.46668)
		(width 0.381)
		(layer "F.Cu")
		(net "GND")
	)
	(segment
		(start 348.77248 -233.877866)
		(end 348.77248 -233.34218)
		(width 0.2032)
		(layer "F.Cu")
		(net "GND")
	)
	(segment
		(start 119.268494 -277.800562)
		(end 119.268748 -278.336502)
		(width 0.254)
		(layer "F.Cu")
		(net "GND")
	)
	(segment
		(start 343.603834 -220.041724)
		(end 343.603834 -219.506038)
		(width 0.254)
		(layer "F.Cu")
		(net "GND")
	)
	(segment
		(start 346.384626 -57.954926)
		(end 346.799662 -57.454546)
		(width 0.2032)
		(layer "F.Cu")
		(net "GND")
	)
	(segment
		(start 272.273014 -240.666778)
		(end 271.168114 -240.666778)
		(width 0.381)
		(layer "F.Cu")
		(net "GND")
	)
	(segment
		(start 39.420546 -306.116736)
		(end 38.315646 -306.116736)
		(width 0.381)
		(layer "F.Cu")
		(net "GND")
	)
	(segment
		(start 133.346952 -17.655032)
		(end 133.346952 -16.550132)
		(width 0.3556)
		(layer "F.Cu")
		(net "GND")
	)
	(segment
		(start 124.437648 -254.197612)
		(end 124.437648 -254.733552)
		(width 0.2032)
		(layer "F.Cu")
		(net "GND")
	)
	(segment
		(start 11.135614 -280.61666)
		(end 12.240514 -280.61666)
		(width 0.381)
		(layer "F.Cu")
		(net "GND")
	)
	(segment
		(start 53.267102 -9.424924)
		(end 53.267102 -8.320024)
		(width 0.3556)
		(layer "F.Cu")
		(net "GND")
	)
	(segment
		(start 353.581462 -267.220192)
		(end 353.581462 -267.755878)
		(width 0.254)
		(layer "F.Cu")
		(net "GND")
	)
	(segment
		(start 161.808414 -224.516696)
		(end 162.913314 -224.516696)
		(width 0.381)
		(layer "F.Cu")
		(net "GND")
	)
	(segment
		(start 27.328114 -314.616592)
		(end 28.433014 -314.616592)
		(width 0.381)
		(layer "F.Cu")
		(net "GND")
	)
	(segment
		(start 33.767014 -316.316614)
		(end 34.871914 -316.316614)
		(width 0.381)
		(layer "F.Cu")
		(net "GND")
	)
	(segment
		(start 92.844366 -231.436164)
		(end 92.844366 -230.900478)
		(width 0.2032)
		(layer "F.Cu")
		(net "GND")
	)
	(segment
		(start 181.444646 -267.016738)
		(end 182.549546 -267.016738)
		(width 0.381)
		(layer "F.Cu")
		(net "GND")
	)
	(segment
		(start 208.176114 -269.566644)
		(end 209.281014 -269.566644)
		(width 0.381)
		(layer "F.Cu")
		(net "GND")
	)
	(segment
		(start 409.748482 -250.866656)
		(end 410.853382 -250.866656)
		(width 0.381)
		(layer "F.Cu")
		(net "GND")
	)
	(segment
		(start 22.123146 -234.716574)
		(end 23.228046 -234.716574)
		(width 0.381)
		(layer "F.Cu")
		(net "GND")
	)
	(segment
		(start 285.150814 -265.316716)
		(end 286.255714 -265.316716)
		(width 0.381)
		(layer "F.Cu")
		(net "GND")
	)
	(segment
		(start 442.185044 -125.46584)
		(end 441.129166 -125.46584)
		(width 0.381)
		(layer "F.Cu")
		(net "GND")
	)
	(segment
		(start 6.579362 -98.516694)
		(end 5.694426 -98.516694)
		(width 0.3556)
		(layer "F.Cu")
		(net "GND")
	)
	(segment
		(start 332.897734 -39.295324)
		(end 333.398114 -39.443152)
		(width 0.2032)
		(layer "F.Cu")
		(net "GND")
	)
	(segment
		(start 242.12169 -247.051068)
		(end 242.09375 -247.079008)
		(width 0.3556)
		(layer "F.Cu")
		(net "GND")
	)
	(segment
		(start 435.557168 -44.44238)
		(end 436.18912 -44.44238)
		(width 0.3556)
		(layer "F.Cu")
		(net "GND")
	)
	(segment
		(start 214.615014 -249.166634)
		(end 215.719914 -249.166634)
		(width 0.381)
		(layer "F.Cu")
		(net "GND")
	)
	(segment
		(start 94.201996 -338.698332)
		(end 94.201996 -339.312504)
		(width 0.381)
		(layer "F.Cu")
		(net "GND")
	)
	(segment
		(start 52.298346 -246.616728)
		(end 53.403246 -246.616728)
		(width 0.381)
		(layer "F.Cu")
		(net "GND")
	)
	(segment
		(start 179.105814 -196.466714)
		(end 178.000914 -196.466714)
		(width 0.381)
		(layer "F.Cu")
		(net "GND")
	)
	(segment
		(start 362.86948 -215.97239)
		(end 362.86948 -215.436704)
		(width 0.2032)
		(layer "F.Cu")
		(net "GND")
	)
	(segment
		(start 378.956316 -254.197612)
		(end 378.956316 -254.733298)
		(width 0.254)
		(layer "F.Cu")
		(net "GND")
	)
	(segment
		(start 97.653094 -277.800562)
		(end 97.653094 -278.336248)
		(width 0.254)
		(layer "F.Cu")
		(net "GND")
	)
	(segment
		(start 131.016248 -276.986492)
		(end 131.016248 -277.522432)
		(width 0.2032)
		(layer "F.Cu")
		(net "GND")
	)
	(segment
		(start 65.047114 -222.816674)
		(end 66.152014 -222.816674)
		(width 0.381)
		(layer "F.Cu")
		(net "GND")
	)
	(segment
		(start 43.520614 -247.466612)
		(end 42.415714 -247.466612)
		(width 0.381)
		(layer "F.Cu")
		(net "GND")
	)
	(segment
		(start 333.274162 -269.66164)
		(end 333.375762 -269.66164)
		(width 0.2032)
		(layer "F.Cu")
		(net "GND")
	)
	(segment
		(start 350.762316 -284.033468)
		(end 350.762062 -284.033722)
		(width 0.254)
		(layer "F.Cu")
		(net "GND")
	)
	(segment
		(start 448.572382 -301.01667)
		(end 447.467482 -301.01667)
		(width 0.381)
		(layer "F.Cu")
		(net "GND")
	)
	(segment
		(start 101.302312 -229.808786)
		(end 101.302312 -229.272846)
		(width 0.2032)
		(layer "F.Cu")
		(net "GND")
	)
	(segment
		(start 301.343314 -268.71676)
		(end 302.448214 -268.71676)
		(width 0.381)
		(layer "F.Cu")
		(net "GND")
	)
	(segment
		(start 375.666762 -274.54479)
		(end 375.667016 -275.08073)
		(width 0.2032)
		(layer "F.Cu")
		(net "GND")
	)
	(segment
		(start 193.20256 -431.424334)
		(end 193.20256 -430.905158)
		(width 0.3556)
		(layer "F.Cu")
		(net "GND")
	)
	(segment
		(start 293.799514 -281.466798)
		(end 294.904414 -281.466798)
		(width 0.381)
		(layer "F.Cu")
		(net "GND")
	)
	(segment
		(start 124.327666 -248.528078)
		(end 124.327412 -248.527824)
		(width 0.2032)
		(layer "F.Cu")
		(net "GND")
	)
	(segment
		(start 111.640112 -228.1809)
		(end 111.640366 -228.180646)
		(width 0.2032)
		(layer "F.Cu")
		(net "GND")
	)
	(segment
		(start 358.640634 -226.017328)
		(end 358.640634 -226.553268)
		(width 0.254)
		(layer "F.Cu")
		(net "GND")
	)
	(segment
		(start 141.10843 -33.466024)
		(end 141.10843 -34.12236)
		(width 0.3556)
		(layer "F.Cu")
		(net "GND")
	)
	(segment
		(start 57.503314 -238.116618)
		(end 58.824114 -238.116618)
		(width 0.381)
		(layer "F.Cu")
		(net "GND")
	)
	(segment
		(start 363.919516 -275.35886)
		(end 363.919262 -275.8948)
		(width 0.2032)
		(layer "F.Cu")
		(net "GND")
	)
	(segment
		(start 176.896014 -295.916604)
		(end 178.000914 -295.916604)
		(width 0.381)
		(layer "F.Cu")
		(net "GND")
	)
	(segment
		(start 21.405596 -385.475226)
		(end 21.456396 -385.526026)
		(width 0.3556)
		(layer "F.Cu")
		(net "GND")
	)
	(segment
		(start 464.764882 -277.216616)
		(end 463.659982 -277.216616)
		(width 0.381)
		(layer "F.Cu")
		(net "GND")
	)
	(segment
		(start 383.046478 -343.391998)
		(end 382.618488 -342.964008)
		(width 0.2032)
		(layer "F.Cu")
		(net "GND")
	)
	(segment
		(start 260.180582 -301.01667)
		(end 259.075682 -301.01667)
		(width 0.381)
		(layer "F.Cu")
		(net "GND")
	)
	(segment
		(start 338.90077 -59.665616)
		(end 338.90077 -59.265312)
		(width 0.2032)
		(layer "F.Cu")
		(net "GND")
	)
	(segment
		(start 23.228046 -307.816758)
		(end 24.332946 -307.816758)
		(width 0.381)
		(layer "F.Cu")
		(net "GND")
	)
	(segment
		(start 124.437648 -256.361184)
		(end 124.437394 -256.361438)
		(width 0.254)
		(layer "F.Cu")
		(net "GND")
	)
	(segment
		(start 84.856066 -222.48368)
		(end 84.385912 -222.761556)
		(width 0.2032)
		(layer "F.Cu")
		(net "GND")
	)
	(segment
		(start 124.907294 -281.591512)
		(end 124.907548 -281.591766)
		(width 0.254)
		(layer "F.Cu")
		(net "GND")
	)
	(segment
		(start 27.328114 -202.416664)
		(end 28.433014 -202.416664)
		(width 0.381)
		(layer "F.Cu")
		(net "GND")
	)
	(segment
		(start 376.136916 -257.45313)
		(end 376.136662 -257.98907)
		(width 0.2032)
		(layer "F.Cu")
		(net "GND")
	)
	(segment
		(start 138.534648 -280.242264)
		(end 138.534648 -280.778204)
		(width 0.2032)
		(layer "F.Cu")
		(net "GND")
	)
	(segment
		(start 171.562014 -213.46668)
		(end 170.457114 -213.46668)
		(width 0.381)
		(layer "F.Cu")
		(net "GND")
	)
	(segment
		(start 333.23657 -44.691046)
		(end 333.439008 -44.343828)
		(width 0.2032)
		(layer "F.Cu")
		(net "GND")
	)
	(segment
		(start 380.725934 -224.111566)
		(end 380.725934 -223.575626)
		(width 0.2032)
		(layer "F.Cu")
		(net "GND")
	)
	(segment
		(start 297.899582 -244.066568)
		(end 299.004482 -244.066568)
		(width 0.381)
		(layer "F.Cu")
		(net "GND")
	)
	(segment
		(start 407.446988 -8.320024)
		(end 407.446988 -7.215124)
		(width 0.3556)
		(layer "F.Cu")
		(net "GND")
	)
	(segment
		(start 63.942214 -205.816708)
		(end 65.047114 -205.816708)
		(width 0.381)
		(layer "F.Cu")
		(net "GND")
	)
	(segment
		(start 18.54708 -8.320024)
		(end 18.54708 -9.424924)
		(width 0.3556)
		(layer "F.Cu")
		(net "GND")
	)
	(segment
		(start 186.23788 -99.259898)
		(end 186.23788 -98.643948)
		(width 0.3556)
		(layer "F.Cu")
		(net "GND")
	)
	(segment
		(start 130.076448 -278.614378)
		(end 130.076448 -279.150318)
		(width 0.254)
		(layer "F.Cu")
		(net "GND")
	)
	(segment
		(start 199.527414 -275.516594)
		(end 200.632314 -275.516594)
		(width 0.381)
		(layer "F.Cu")
		(net "GND")
	)
	(segment
		(start 138.534648 -255.825498)
		(end 138.065002 -255.547368)
		(width 0.254)
		(layer "F.Cu")
		(net "GND")
	)
	(segment
		(start 432.379882 -271.266666)
		(end 433.484782 -271.266666)
		(width 0.381)
		(layer "F.Cu")
		(net "GND")
	)
	(segment
		(start 19.784314 -261.066788)
		(end 20.889214 -261.066788)
		(width 0.381)
		(layer "F.Cu")
		(net "GND")
	)
	(segment
		(start 428.279814 -238.966756)
		(end 429.384714 -238.966756)
		(width 0.381)
		(layer "F.Cu")
		(net "GND")
	)
	(segment
		(start 126.317248 -270.475456)
		(end 126.316994 -271.011396)
		(width 0.2032)
		(layer "F.Cu")
		(net "GND")
	)
	(segment
		(start 8.140446 -306.116736)
		(end 9.245346 -306.116736)
		(width 0.381)
		(layer "F.Cu")
		(net "GND")
	)
	(segment
		(start 459.559914 -301.866808)
		(end 460.664814 -301.866808)
		(width 0.381)
		(layer "F.Cu")
		(net "GND")
	)
	(segment
		(start 95.193866 -220.855794)
		(end 95.193866 -220.319854)
		(width 0.2032)
		(layer "F.Cu")
		(net "GND")
	)
	(segment
		(start 385.07797 -258.811268)
		(end 385.069842 -258.80314)
		(width 0.254)
		(layer "F.Cu")
		(net "GND")
	)
	(segment
		(start 172.795946 -300.166786)
		(end 173.900846 -300.166786)
		(width 0.381)
		(layer "F.Cu")
		(net "GND")
	)
	(segment
		(start 412.956756 -11.26998)
		(end 412.956756 -12.37488)
		(width 0.3556)
		(layer "F.Cu")
		(net "GND")
	)
	(segment
		(start 190.093346 -260.21665)
		(end 188.988446 -260.21665)
		(width 0.381)
		(layer "F.Cu")
		(net "GND")
	)
	(segment
		(start 194.193414 -232.166668)
		(end 193.088514 -232.166668)
		(width 0.381)
		(layer "F.Cu")
		(net "GND")
	)
	(segment
		(start 275.268182 -216.866724)
		(end 274.163282 -216.866724)
		(width 0.381)
		(layer "F.Cu")
		(net "GND")
	)
	(segment
		(start 211.619846 -220.266768)
		(end 212.724746 -220.266768)
		(width 0.381)
		(layer "F.Cu")
		(net "GND")
	)
	(segment
		(start 193.088514 -301.01667)
		(end 194.193414 -301.01667)
		(width 0.381)
		(layer "F.Cu")
		(net "GND")
	)
	(segment
		(start 276.373082 -202.416664)
		(end 275.268182 -202.416664)
		(width 0.381)
		(layer "F.Cu")
		(net "GND")
	)
	(segment
		(start 26.223214 -275.516594)
		(end 27.328114 -275.516594)
		(width 0.381)
		(layer "F.Cu")
		(net "GND")
	)
	(segment
		(start 428.279814 -295.06672)
		(end 429.384714 -295.06672)
		(width 0.381)
		(layer "F.Cu")
		(net "GND")
	)
	(segment
		(start 38.315646 -292.516814)
		(end 37.210746 -292.516814)
		(width 0.381)
		(layer "F.Cu")
		(net "GND")
	)
	(segment
		(start 129.136648 -264.499852)
		(end 129.136394 -264.500106)
		(width 0.2032)
		(layer "F.Cu")
		(net "GND")
	)
	(segment
		(start 207.071214 -303.566576)
		(end 208.176114 -303.566576)
		(width 0.381)
		(layer "F.Cu")
		(net "GND")
	)
	(segment
		(start 188.988446 -261.916672)
		(end 187.883546 -261.916672)
		(width 0.381)
		(layer "F.Cu")
		(net "GND")
	)
	(segment
		(start 340.784434 -239.575086)
		(end 340.784434 -239.0394)
		(width 0.2032)
		(layer "F.Cu")
		(net "GND")
	)
	(segment
		(start 202.971146 -287.416748)
		(end 204.076046 -287.416748)
		(width 0.381)
		(layer "F.Cu")
		(net "GND")
	)
	(segment
		(start 129.606294 -258.2672)
		(end 129.606294 -258.80314)
		(width 0.2032)
		(layer "F.Cu")
		(net "GND")
	)
	(segment
		(start 204.076046 -260.21665)
		(end 205.180946 -260.21665)
		(width 0.381)
		(layer "F.Cu")
		(net "GND")
	)
	(segment
		(start 219.94495 -50.25009)
		(end 219.94495 -49.911)
		(width 0.3556)
		(layer "F.Cu")
		(net "GND")
	)
	(segment
		(start 366.15878 -223.297496)
		(end 366.15878 -222.76181)
		(width 0.254)
		(layer "F.Cu")
		(net "GND")
	)
	(segment
		(start 34.871914 -211.766658)
		(end 35.976814 -211.766658)
		(width 0.381)
		(layer "F.Cu")
		(net "GND")
	)
	(segment
		(start 276.373082 -267.866622)
		(end 275.268182 -267.866622)
		(width 0.381)
		(layer "F.Cu")
		(net "GND")
	)
	(segment
		(start 137.256012 -260.630162)
		(end 136.848088 -260.38937)
		(width 0.088646)
		(layer "F.Cu")
		(net "GND")
	)
	(segment
		(start 43.520614 -205.816708)
		(end 42.415714 -205.816708)
		(width 0.381)
		(layer "F.Cu")
		(net "GND")
	)
	(segment
		(start 110.340648 -260.708902)
		(end 110.340648 -261.244842)
		(width 0.254)
		(layer "F.Cu")
		(net "GND")
	)
	(segment
		(start 176.712372 -427.446948)
		(end 176.57953 -427.446948)
		(width 0.3556)
		(layer "F.Cu")
		(net "GND")
	)
	(segment
		(start 436.928514 -199.01662)
		(end 438.033414 -199.01662)
		(width 0.381)
		(layer "F.Cu")
		(net "GND")
	)
	(segment
		(start 372.377716 -280.242264)
		(end 372.377462 -280.778204)
		(width 0.254)
		(layer "F.Cu")
		(net "GND")
	)
	(segment
		(start 126.317248 -280.242264)
		(end 126.317248 -280.778204)
		(width 0.2032)
		(layer "F.Cu")
		(net "GND")
	)
	(segment
		(start 285.150814 -281.466798)
		(end 286.255714 -281.466798)
		(width 0.381)
		(layer "F.Cu")
		(net "GND")
	)
	(segment
		(start 132.785866 -243.644928)
		(end 132.785866 -243.108988)
		(width 0.2032)
		(layer "F.Cu")
		(net "GND")
	)
	(segment
		(start 327.41489 -40.946578)
		(end 328.244962 -40.946578)
		(width 0.2032)
		(layer "F.Cu")
		(net "GND")
	)
	(segment
		(start 185.544714 -222.816674)
		(end 186.649614 -222.816674)
		(width 0.381)
		(layer "F.Cu")
		(net "GND")
	)
	(segment
		(start 286.255714 -295.06672)
		(end 287.360614 -295.06672)
		(width 0.381)
		(layer "F.Cu")
		(net "GND")
	)
	(segment
		(start 14.579346 -311.216802)
		(end 15.684246 -311.216802)
		(width 0.381)
		(layer "F.Cu")
		(net "GND")
	)
	(segment
		(start 106.471466 -220.855794)
		(end 106.471466 -220.319854)
		(width 0.2032)
		(layer "F.Cu")
		(net "GND")
	)
	(segment
		(start 405.64689 -8.320024)
		(end 405.64689 -7.215124)
		(width 0.3556)
		(layer "F.Cu")
		(net "GND")
	)
	(segment
		(start 119.079264 -334.191102)
		(end 118.78564 -334.191102)
		(width 0.2032)
		(layer "F.Cu")
		(net "GND")
	)
	(segment
		(start 115.399312 -226.553268)
		(end 115.399312 -226.017582)
		(width 0.254)
		(layer "F.Cu")
		(net "GND")
	)
	(segment
		(start 99.532694 -278.336248)
		(end 99.532948 -278.336502)
		(width 0.2032)
		(layer "F.Cu")
		(net "GND")
	)
	(segment
		(start 117.388894 -266.405868)
		(end 117.389148 -266.941808)
		(width 0.2032)
		(layer "F.Cu")
		(net "GND")
	)
	(segment
		(start 91.434666 -242.017042)
		(end 91.434412 -242.016788)
		(width 0.2032)
		(layer "F.Cu")
		(net "GND")
	)
	(segment
		(start 373.787162 -263.68629)
		(end 373.787416 -263.686544)
		(width 0.2032)
		(layer "F.Cu")
		(net "GND")
	)
	(segment
		(start 455.011282 -211.766658)
		(end 456.116182 -211.766658)
		(width 0.381)
		(layer "F.Cu")
		(net "GND")
	)
	(segment
		(start 90.604848 -278.614378)
		(end 90.604594 -279.150318)
		(width 0.2032)
		(layer "F.Cu")
		(net "GND")
	)
	(segment
		(start 96.243394 -266.128246)
		(end 96.243394 -265.592306)
		(width 0.254)
		(layer "F.Cu")
		(net "GND")
	)
	(segment
		(start 93.314012 -245.272306)
		(end 93.314012 -244.73662)
		(width 0.2032)
		(layer "F.Cu")
		(net "GND")
	)
	(segment
		(start 223.8121 -48.78197)
		(end 223.06788 -48.78197)
		(width 0.3556)
		(layer "F.Cu")
		(net "GND")
	)
	(segment
		(start 267.724382 -219.41663)
		(end 268.829282 -219.41663)
		(width 0.381)
		(layer "F.Cu")
		(net "GND")
	)
	(segment
		(start 12.240514 -216.866724)
		(end 13.345414 -216.866724)
		(width 0.381)
		(layer "F.Cu")
		(net "GND")
	)
	(segment
		(start 56.398414 -244.066568)
		(end 57.503314 -244.066568)
		(width 0.381)
		(layer "F.Cu")
		(net "GND")
	)
	(segment
		(start 394.899896 -63.232284)
		(end 394.899896 -65.064894)
		(width 0.3556)
		(layer "F.Cu")
		(net "GND")
	)
	(segment
		(start 367.208816 -281.056334)
		(end 367.208816 -281.59202)
		(width 0.254)
		(layer "F.Cu")
		(net "GND")
	)
	(segment
		(start 333.679292 -339.309964)
		(end 333.679292 -339.52561)
		(width 0.2032)
		(layer "F.Cu")
		(net "GND")
	)
	(segment
		(start 193.088514 -194.766692)
		(end 191.983614 -194.766692)
		(width 0.381)
		(layer "F.Cu")
		(net "GND")
	)
	(segment
		(start 292.74643 -410.68625)
		(end 292.8493 -410.58338)
		(width 0.3556)
		(layer "F.Cu")
		(net "GND")
	)
	(segment
		(start 361.45978 -234.69219)
		(end 361.460034 -234.691936)
		(width 0.2032)
		(layer "F.Cu")
		(net "GND")
	)
	(segment
		(start 113.519712 -236.319822)
		(end 113.519712 -235.78439)
		(width 0.254)
		(layer "F.Cu")
		(net "GND")
	)
	(segment
		(start 53.403246 -217.716608)
		(end 54.724046 -217.716608)
		(width 0.381)
		(layer "F.Cu")
		(net "GND")
	)
	(segment
		(start 211.619846 -267.016738)
		(end 212.724746 -267.016738)
		(width 0.381)
		(layer "F.Cu")
		(net "GND")
	)
	(segment
		(start 340.78418 -237.947454)
		(end 340.784434 -237.947454)
		(width 0.254)
		(layer "F.Cu")
		(net "GND")
	)
	(segment
		(start 126.676912 -228.1809)
		(end 126.677166 -228.180646)
		(width 0.2032)
		(layer "F.Cu")
		(net "GND")
	)
	(segment
		(start 162.913314 -272.966688)
		(end 161.579814 -272.966688)
		(width 0.381)
		(layer "F.Cu")
		(net "GND")
	)
	(segment
		(start 372.26748 -246.900192)
		(end 372.26748 -246.364506)
		(width 0.2032)
		(layer "F.Cu")
		(net "GND")
	)
	(segment
		(start 424.836082 -250.866656)
		(end 425.940982 -250.866656)
		(width 0.381)
		(layer "F.Cu")
		(net "GND")
	)
	(segment
		(start 23.228046 -217.716608)
		(end 24.332946 -217.716608)
		(width 0.381)
		(layer "F.Cu")
		(net "GND")
	)
	(segment
		(start 200.632314 -233.86669)
		(end 201.737214 -233.86669)
		(width 0.381)
		(layer "F.Cu")
		(net "GND")
	)
	(segment
		(start 424.836082 -224.516696)
		(end 425.940982 -224.516696)
		(width 0.381)
		(layer "F.Cu")
		(net "GND")
	)
	(segment
		(start 30.771846 -223.666558)
		(end 31.876746 -223.666558)
		(width 0.381)
		(layer "F.Cu")
		(net "GND")
	)
	(segment
		(start 130.906266 -220.855794)
		(end 130.906266 -220.319854)
		(width 0.2032)
		(layer "F.Cu")
		(net "GND")
	)
	(segment
		(start 338.54517 -281.87015)
		(end 338.544916 -282.405836)
		(width 0.254)
		(layer "F.Cu")
		(net "GND")
	)
	(segment
		(start 196.532246 -281.466798)
		(end 195.427346 -281.466798)
		(width 0.381)
		(layer "F.Cu")
		(net "GND")
	)
	(segment
		(start 188.988446 -195.616576)
		(end 187.883546 -195.616576)
		(width 0.381)
		(layer "F.Cu")
		(net "GND")
	)
	(segment
		(start 344.046302 -338.86013)
		(end 344.673682 -338.86013)
		(width 0.381)
		(layer "F.Cu")
		(net "GND")
	)
	(segment
		(start 218.360752 -44.788328)
		(end 219.325952 -44.788328)
		(width 0.3556)
		(layer "F.Cu")
		(net "GND")
	)
	(segment
		(start 215.719914 -289.966654)
		(end 216.824814 -289.966654)
		(width 0.381)
		(layer "F.Cu")
		(net "GND")
	)
	(segment
		(start 367.568734 -220.855794)
		(end 367.568734 -220.319854)
		(width 0.2032)
		(layer "F.Cu")
		(net "GND")
	)
	(segment
		(start 20.989798 -414.277302)
		(end 20.989798 -413.782002)
		(width 0.3556)
		(layer "F.Cu")
		(net "GND")
	)
	(segment
		(start 181.444646 -251.716794)
		(end 182.549546 -251.716794)
		(width 0.381)
		(layer "F.Cu")
		(net "GND")
	)
	(segment
		(start 38.315646 -206.666592)
		(end 37.210746 -206.666592)
		(width 0.381)
		(layer "F.Cu")
		(net "GND")
	)
	(segment
		(start 108.461048 -279.150064)
		(end 108.460794 -279.150318)
		(width 0.254)
		(layer "F.Cu")
		(net "GND")
	)
	(segment
		(start 196.532246 -292.516814)
		(end 195.427346 -292.516814)
		(width 0.381)
		(layer "F.Cu")
		(net "GND")
	)
	(segment
		(start 453.121014 -248.31675)
		(end 452.016114 -248.31675)
		(width 0.381)
		(layer "F.Cu")
		(net "GND")
	)
	(segment
		(start 422.945814 -279.766776)
		(end 421.840914 -279.766776)
		(width 0.381)
		(layer "F.Cu")
		(net "GND")
	)
	(segment
		(start 29.666946 -208.366614)
		(end 30.771846 -208.366614)
		(width 0.381)
		(layer "F.Cu")
		(net "GND")
	)
	(segment
		(start 175.005746 -244.916706)
		(end 173.900846 -244.916706)
		(width 0.381)
		(layer "F.Cu")
		(net "GND")
	)
	(segment
		(start 381.305562 -282.683966)
		(end 381.305816 -282.68422)
		(width 0.254)
		(layer "F.Cu")
		(net "GND")
	)
	(segment
		(start 452.016114 -199.01662)
		(end 450.911214 -199.01662)
		(width 0.381)
		(layer "F.Cu")
		(net "GND")
	)
	(segment
		(start 418.397182 -314.616592)
		(end 417.292282 -314.616592)
		(width 0.381)
		(layer "F.Cu")
		(net "GND")
	)
	(segment
		(start 101.433884 -392.63574)
		(end 101.433884 -393.03579)
		(width 0.3556)
		(layer "F.Cu")
		(net "GND")
	)
	(segment
		(start 199.527414 -215.166702)
		(end 200.632314 -215.166702)
		(width 0.381)
		(layer "F.Cu")
		(net "GND")
	)
	(segment
		(start 115.399566 -220.041724)
		(end 115.399566 -219.506038)
		(width 0.254)
		(layer "F.Cu")
		(net "GND")
	)
	(segment
		(start 444.472314 -292.516814)
		(end 445.577214 -292.516814)
		(width 0.381)
		(layer "F.Cu")
		(net "GND")
	)
	(segment
		(start 8.140446 -287.416748)
		(end 9.245346 -287.416748)
		(width 0.381)
		(layer "F.Cu")
		(net "GND")
	)
	(segment
		(start 356.870762 -274.54479)
		(end 356.870762 -275.08073)
		(width 0.254)
		(layer "F.Cu")
		(net "GND")
	)
	(segment
		(start 90.134694 -255.011682)
		(end 90.134694 -255.547622)
		(width 0.2032)
		(layer "F.Cu")
		(net "GND")
	)
	(segment
		(start 44.754546 -263.616694)
		(end 45.859446 -263.616694)
		(width 0.381)
		(layer "F.Cu")
		(net "GND")
	)
	(segment
		(start 95.193612 -250.15571)
		(end 95.193612 -249.620024)
		(width 0.2032)
		(layer "F.Cu")
		(net "GND")
	)
	(segment
		(start 260.180582 -210.066636)
		(end 259.075682 -210.066636)
		(width 0.381)
		(layer "F.Cu")
		(net "GND")
	)
	(segment
		(start 275.268182 -269.566644)
		(end 274.163282 -269.566644)
		(width 0.381)
		(layer "F.Cu")
		(net "GND")
	)
	(segment
		(start 157.708346 -240.666778)
		(end 158.813246 -240.666778)
		(width 0.381)
		(layer "F.Cu")
		(net "GND")
	)
	(segment
		(start 124.437648 -267.219938)
		(end 124.437394 -267.755878)
		(width 0.2032)
		(layer "F.Cu")
		(net "GND")
	)
	(segment
		(start 312.987182 -286.56661)
		(end 314.092082 -286.56661)
		(width 0.381)
		(layer "F.Cu")
		(net "GND")
	)
	(segment
		(start 185.544714 -200.716642)
		(end 186.649614 -200.716642)
		(width 0.381)
		(layer "F.Cu")
		(net "GND")
	)
	(segment
		(start 236.7153 -247.744488)
		(end 237.92942 -246.530368)
		(width 0.3556)
		(layer "F.Cu")
		(net "GND")
	)
	(segment
		(start 443.367414 -283.166566)
		(end 444.472314 -283.166566)
		(width 0.381)
		(layer "F.Cu")
		(net "GND")
	)
	(segment
		(start 108.820966 -231.436164)
		(end 108.820966 -230.900478)
		(width 0.2032)
		(layer "F.Cu")
		(net "GND")
	)
	(segment
		(start 33.767014 -262.76681)
		(end 34.871914 -262.76681)
		(width 0.381)
		(layer "F.Cu")
		(net "GND")
	)
	(segment
		(start 184.439814 -241.516662)
		(end 185.544714 -241.516662)
		(width 0.381)
		(layer "F.Cu")
		(net "GND")
	)
	(segment
		(start 391.411206 -157.997652)
		(end 391.411206 -156.613098)
		(width 0.3556)
		(layer "F.Cu")
		(net "GND")
	)
	(segment
		(start 202.971146 -300.166786)
		(end 204.076046 -300.166786)
		(width 0.381)
		(layer "F.Cu")
		(net "GND")
	)
	(segment
		(start 130.906012 -238.76127)
		(end 130.906012 -238.225584)
		(width 0.2032)
		(layer "F.Cu")
		(net "GND")
	)
	(segment
		(start 14.579346 -206.666592)
		(end 15.684246 -206.666592)
		(width 0.381)
		(layer "F.Cu")
		(net "GND")
	)
	(segment
		(start 8.38708 -97.236788)
		(end 8.74776 -97.236788)
		(width 0.254)
		(layer "F.Cu")
		(net "GND")
	)
	(segment
		(start 120.098312 -216.250774)
		(end 120.098566 -216.25052)
		(width 0.254)
		(layer "F.Cu")
		(net "GND")
	)
	(segment
		(start 27.328114 -196.466714)
		(end 26.223214 -196.466714)
		(width 0.381)
		(layer "F.Cu")
		(net "GND")
	)
	(segment
		(start 161.808414 -194.766692)
		(end 162.913314 -194.766692)
		(width 0.381)
		(layer "F.Cu")
		(net "GND")
	)
	(segment
		(start 278.711914 -307.816758)
		(end 277.607014 -307.816758)
		(width 0.381)
		(layer "F.Cu")
		(net "GND")
	)
	(segment
		(start 193.088514 -249.166634)
		(end 191.983614 -249.166634)
		(width 0.381)
		(layer "F.Cu")
		(net "GND")
	)
	(segment
		(start 19.784314 -238.116618)
		(end 20.889214 -238.116618)
		(width 0.381)
		(layer "F.Cu")
		(net "GND")
	)
	(segment
		(start 341.72398 -242.830858)
		(end 341.72398 -242.295172)
		(width 0.2032)
		(layer "F.Cu")
		(net "GND")
	)
	(segment
		(start 14.579346 -287.416748)
		(end 15.684246 -287.416748)
		(width 0.381)
		(layer "F.Cu")
		(net "GND")
	)
	(segment
		(start 418.397182 -267.866622)
		(end 417.292282 -267.866622)
		(width 0.381)
		(layer "F.Cu")
		(net "GND")
	)
	(segment
		(start 60.947046 -251.716794)
		(end 62.051946 -251.716794)
		(width 0.381)
		(layer "F.Cu")
		(net "GND")
	)
	(segment
		(start 166.357046 -236.416596)
		(end 167.684196 -236.416596)
		(width 0.381)
		(layer "F.Cu")
		(net "GND")
	)
	(segment
		(start 115.95608 -122.532648)
		(end 115.95608 -123.148598)
		(width 0.3556)
		(layer "F.Cu")
		(net "GND")
	)
	(segment
		(start 276.373082 -312.91657)
		(end 275.268182 -312.91657)
		(width 0.381)
		(layer "F.Cu")
		(net "GND")
	)
	(segment
		(start 306.99075 -23.7744)
		(end 305.5112 -23.7744)
		(width 0.3556)
		(layer "F.Cu")
		(net "GND")
	)
	(segment
		(start 53.403246 -242.3668)
		(end 54.508146 -242.3668)
		(width 0.381)
		(layer "F.Cu")
		(net "GND")
	)
	(segment
		(start 425.940982 -262.76681)
		(end 427.045882 -262.76681)
		(width 0.381)
		(layer "F.Cu")
		(net "GND")
	)
	(segment
		(start 277.607014 -260.21665)
		(end 278.711914 -260.21665)
		(width 0.381)
		(layer "F.Cu")
		(net "GND")
	)
	(segment
		(start 15.684246 -206.666592)
		(end 16.789146 -206.666592)
		(width 0.381)
		(layer "F.Cu")
		(net "GND")
	)
	(segment
		(start 374.726962 -255.011682)
		(end 374.726962 -255.547622)
		(width 0.2032)
		(layer "F.Cu")
		(net "GND")
	)
	(segment
		(start 106.471466 -217.600276)
		(end 106.471466 -217.064336)
		(width 0.2032)
		(layer "F.Cu")
		(net "GND")
	)
	(segment
		(start 418.397182 -224.516696)
		(end 417.292282 -224.516696)
		(width 0.381)
		(layer "F.Cu")
		(net "GND")
	)
	(segment
		(start 343.243916 -283.497782)
		(end 343.243916 -284.033468)
		(width 0.254)
		(layer "F.Cu")
		(net "GND")
	)
	(segment
		(start 261.285482 -294.216582)
		(end 260.180582 -294.216582)
		(width 0.381)
		(layer "F.Cu")
		(net "GND")
	)
	(segment
		(start 169.867072 -13.600176)
		(end 169.867072 -12.495022)
		(width 0.3556)
		(layer "F.Cu")
		(net "GND")
	)
	(segment
		(start 179.105814 -207.51673)
		(end 178.000914 -207.51673)
		(width 0.381)
		(layer "F.Cu")
		(net "GND")
	)
	(segment
		(start 297.899582 -194.766692)
		(end 299.004482 -194.766692)
		(width 0.381)
		(layer "F.Cu")
		(net "GND")
	)
	(segment
		(start 42.415714 -200.716642)
		(end 41.310814 -200.716642)
		(width 0.381)
		(layer "F.Cu")
		(net "GND")
	)
	(segment
		(start 187.883546 -307.816758)
		(end 188.988446 -307.816758)
		(width 0.381)
		(layer "F.Cu")
		(net "GND")
	)
	(segment
		(start 199.527414 -239.81664)
		(end 200.632314 -239.81664)
		(width 0.381)
		(layer "F.Cu")
		(net "GND")
	)
	(segment
		(start 345.48318 -239.57534)
		(end 345.483434 -239.575086)
		(width 0.2032)
		(layer "F.Cu")
		(net "GND")
	)
	(segment
		(start 94.254066 -243.644928)
		(end 94.253812 -243.644674)
		(width 0.2032)
		(layer "F.Cu")
		(net "GND")
	)
	(segment
		(start 405.648414 -289.11677)
		(end 406.753314 -289.11677)
		(width 0.381)
		(layer "F.Cu")
		(net "GND")
	)
	(segment
		(start 364.27918 -226.017582)
		(end 364.279434 -226.017328)
		(width 0.254)
		(layer "F.Cu")
		(net "GND")
	)
	(segment
		(start 123.387866 -240.389156)
		(end 123.387612 -240.388902)
		(width 0.2032)
		(layer "F.Cu")
		(net "GND")
	)
	(segment
		(start 22.123146 -260.21665)
		(end 23.228046 -260.21665)
		(width 0.381)
		(layer "F.Cu")
		(net "GND")
	)
	(segment
		(start 39.420546 -317.166752)
		(end 38.315646 -317.166752)
		(width 0.381)
		(layer "F.Cu")
		(net "GND")
	)
	(segment
		(start 369.918234 -220.041724)
		(end 369.918234 -219.506038)
		(width 0.254)
		(layer "F.Cu")
		(net "GND")
	)
	(segment
		(start 29.666946 -221.96679)
		(end 30.771846 -221.96679)
		(width 0.381)
		(layer "F.Cu")
		(net "GND")
	)
	(segment
		(start 374.61698 -216.250774)
		(end 374.617234 -216.25052)
		(width 0.254)
		(layer "F.Cu")
		(net "GND")
	)
	(segment
		(start 449.573904 -118.336822)
		(end 448.8942 -118.336822)
		(width 0.3556)
		(layer "F.Cu")
		(net "GND")
	)
	(segment
		(start 366.269016 -270.167862)
		(end 366.269016 -270.19758)
		(width 0.254)
		(layer "F.Cu")
		(net "GND")
	)
	(segment
		(start 215.719914 -280.61666)
		(end 216.824814 -280.61666)
		(width 0.381)
		(layer "F.Cu")
		(net "GND")
	)
	(segment
		(start 427.045882 -303.566576)
		(end 425.940982 -303.566576)
		(width 0.381)
		(layer "F.Cu")
		(net "GND")
	)
	(segment
		(start 185.544714 -301.01667)
		(end 186.649614 -301.01667)
		(width 0.381)
		(layer "F.Cu")
		(net "GND")
	)
	(segment
		(start 22.123146 -229.616762)
		(end 23.228046 -229.616762)
		(width 0.381)
		(layer "F.Cu")
		(net "GND")
	)
	(segment
		(start 120.678448 -278.614378)
		(end 120.678448 -279.150318)
		(width 0.254)
		(layer "F.Cu")
		(net "GND")
	)
	(segment
		(start 363.339634 -229.808532)
		(end 363.339634 -229.272846)
		(width 0.2032)
		(layer "F.Cu")
		(net "GND")
	)
	(segment
		(start 173.900846 -290.816792)
		(end 175.005746 -290.816792)
		(width 0.381)
		(layer "F.Cu")
		(net "GND")
	)
	(segment
		(start 166.357046 -260.21665)
		(end 167.461946 -260.21665)
		(width 0.381)
		(layer "F.Cu")
		(net "GND")
	)
	(segment
		(start 425.940982 -261.066788)
		(end 427.045882 -261.066788)
		(width 0.381)
		(layer "F.Cu")
		(net "GND")
	)
	(segment
		(start 12.240514 -289.966654)
		(end 13.345414 -289.966654)
		(width 0.381)
		(layer "F.Cu")
		(net "GND")
	)
	(segment
		(start 12.240514 -295.916604)
		(end 13.345414 -295.916604)
		(width 0.381)
		(layer "F.Cu")
		(net "GND")
	)
	(segment
		(start 87.675466 -248.528078)
		(end 87.675466 -247.992138)
		(width 0.2032)
		(layer "F.Cu")
		(net "GND")
	)
	(segment
		(start 176.140364 -335.483962)
		(end 177.156364 -335.483962)
		(width 0.508)
		(layer "F.Cu")
		(net "GND")
	)
	(segment
		(start 199.527414 -301.01667)
		(end 200.632314 -301.01667)
		(width 0.381)
		(layer "F.Cu")
		(net "GND")
	)
	(segment
		(start 304.338482 -241.516662)
		(end 305.443382 -241.516662)
		(width 0.381)
		(layer "F.Cu")
		(net "GND")
	)
	(segment
		(start 44.754546 -221.96679)
		(end 45.859446 -221.96679)
		(width 0.381)
		(layer "F.Cu")
		(net "GND")
	)
	(segment
		(start 48.854614 -244.066568)
		(end 49.959514 -244.066568)
		(width 0.381)
		(layer "F.Cu")
		(net "GND")
	)
	(segment
		(start 448.572382 -211.766658)
		(end 447.467482 -211.766658)
		(width 0.381)
		(layer "F.Cu")
		(net "GND")
	)
	(segment
		(start 113.519712 -231.436418)
		(end 113.519966 -231.436164)
		(width 0.2032)
		(layer "F.Cu")
		(net "GND")
	)
	(segment
		(start 89.664794 -259.081016)
		(end 89.664794 -259.616956)
		(width 0.2032)
		(layer "F.Cu")
		(net "GND")
	)
	(segment
		(start 307.782214 -292.516814)
		(end 308.887114 -292.516814)
		(width 0.381)
		(layer "F.Cu")
		(net "GND")
	)
	(segment
		(start 186.649614 -278.916638)
		(end 185.544714 -278.916638)
		(width 0.381)
		(layer "F.Cu")
		(net "GND")
	)
	(segment
		(start 182.549546 -300.166786)
		(end 181.444646 -300.166786)
		(width 0.381)
		(layer "F.Cu")
		(net "GND")
	)
	(segment
		(start 118.915942 -37.355526)
		(end 119.714264 -37.355526)
		(width 0.3556)
		(layer "F.Cu")
		(net "GND")
	)
	(segment
		(start 346.973906 -37.63518)
		(end 346.559378 -37.63518)
		(width 0.254)
		(layer "F.Cu")
		(net "GND")
	)
	(segment
		(start 135.781542 -97.25787)
		(end 135.94588 -97.422208)
		(width 0.254)
		(layer "F.Cu")
		(net "GND")
	)
	(segment
		(start 134.775448 -257.45313)
		(end 134.775448 -257.988816)
		(width 0.2032)
		(layer "F.Cu")
		(net "GND")
	)
	(segment
		(start 260.180582 -200.716642)
		(end 259.075682 -200.716642)
		(width 0.381)
		(layer "F.Cu")
		(net "GND")
	)
	(segment
		(start 294.904414 -238.966756)
		(end 293.799514 -238.966756)
		(width 0.381)
		(layer "F.Cu")
		(net "GND")
	)
	(segment
		(start 29.666946 -261.916672)
		(end 30.771846 -261.916672)
		(width 0.381)
		(layer "F.Cu")
		(net "GND")
	)
	(segment
		(start 153.99004 -41.439338)
		(end 153.61793 -41.811448)
		(width 0.3556)
		(layer "F.Cu")
		(net "GND")
	)
	(segment
		(start 312.987182 -241.516662)
		(end 314.092082 -241.516662)
		(width 0.381)
		(layer "F.Cu")
		(net "GND")
	)
	(segment
		(start 129.606294 -256.639314)
		(end 129.606294 -256.807462)
		(width 0.2032)
		(layer "F.Cu")
		(net "GND")
	)
	(segment
		(start 305.443382 -205.816708)
		(end 306.548282 -205.816708)
		(width 0.381)
		(layer "F.Cu")
		(net "GND")
	)
	(segment
		(start 294.904414 -279.766776)
		(end 293.799514 -279.766776)
		(width 0.381)
		(layer "F.Cu")
		(net "GND")
	)
	(segment
		(start 308.887114 -268.71676)
		(end 309.992014 -268.71676)
		(width 0.381)
		(layer "F.Cu")
		(net "GND")
	)
	(segment
		(start 293.799514 -214.316564)
		(end 292.694614 -214.316564)
		(width 0.381)
		(layer "F.Cu")
		(net "GND")
	)
	(segment
		(start 129.136648 -270.475456)
		(end 129.136394 -271.011396)
		(width 0.2032)
		(layer "F.Cu")
		(net "GND")
	)
	(segment
		(start 130.546094 -277.800562)
		(end 130.546094 -278.336502)
		(width 0.2032)
		(layer "F.Cu")
		(net "GND")
	)
	(segment
		(start 378.486162 -279.428194)
		(end 378.486416 -279.964134)
		(width 0.254)
		(layer "F.Cu")
		(net "GND")
	)
	(segment
		(start 100.362512 -237.947454)
		(end 100.362766 -237.947454)
		(width 0.254)
		(layer "F.Cu")
		(net "GND")
	)
	(segment
		(start 348.772734 -214.344758)
		(end 348.772734 -213.732618)
		(width 0.254)
		(layer "F.Cu")
		(net "GND")
	)
	(segment
		(start 215.719914 -222.816674)
		(end 216.824814 -222.816674)
		(width 0.381)
		(layer "F.Cu")
		(net "GND")
	)
	(segment
		(start 15.684246 -268.71676)
		(end 16.789146 -268.71676)
		(width 0.381)
		(layer "F.Cu")
		(net "GND")
	)
	(segment
		(start 378.956316 -286.7533)
		(end 378.956316 -287.288986)
		(width 0.254)
		(layer "F.Cu")
		(net "GND")
	)
	(segment
		(start 254.975614 -279.766776)
		(end 256.080514 -279.766776)
		(width 0.381)
		(layer "F.Cu")
		(net "GND")
	)
	(segment
		(start 444.472314 -220.266768)
		(end 445.577214 -220.266768)
		(width 0.381)
		(layer "F.Cu")
		(net "GND")
	)
	(segment
		(start 410.853382 -294.216582)
		(end 411.958282 -294.216582)
		(width 0.381)
		(layer "F.Cu")
		(net "GND")
	)
	(segment
		(start 45.859446 -289.11677)
		(end 46.964346 -289.11677)
		(width 0.381)
		(layer "F.Cu")
		(net "GND")
	)
	(segment
		(start 340.562946 -46.100746)
		(end 340.290658 -45.630846)
		(width 0.2032)
		(layer "F.Cu")
		(net "GND")
	)
	(segment
		(start 413.192214 -279.766776)
		(end 414.297114 -279.766776)
		(width 0.381)
		(layer "F.Cu")
		(net "GND")
	)
	(segment
		(start 170.955716 -109.775498)
		(end 170.555666 -109.375448)
		(width 0.3556)
		(layer "F.Cu")
		(net "GND")
	)
	(segment
		(start 364.859316 -264.499852)
		(end 364.859062 -264.500106)
		(width 0.2032)
		(layer "F.Cu")
		(net "GND")
	)
	(segment
		(start 340.78418 -246.08663)
		(end 340.78418 -245.55069)
		(width 0.2032)
		(layer "F.Cu")
		(net "GND")
	)
	(segment
		(start 204.076046 -208.366614)
		(end 205.180946 -208.366614)
		(width 0.381)
		(layer "F.Cu")
		(net "GND")
	)
	(segment
		(start 134.305294 -255.011682)
		(end 134.305294 -255.547368)
		(width 0.2032)
		(layer "F.Cu")
		(net "GND")
	)
	(segment
		(start 419.502082 -224.516696)
		(end 418.397182 -224.516696)
		(width 0.381)
		(layer "F.Cu")
		(net "GND")
	)
	(segment
		(start 304.338482 -297.616626)
		(end 305.443382 -297.616626)
		(width 0.381)
		(layer "F.Cu")
		(net "GND")
	)
	(segment
		(start 101.433884 -396.44574)
		(end 100.824284 -396.44574)
		(width 0.3556)
		(layer "F.Cu")
		(net "GND")
	)
	(segment
		(start 394.899896 -50.894996)
		(end 394.899896 -48.934878)
		(width 0.3556)
		(layer "F.Cu")
		(net "GND")
	)
	(segment
		(start 409.60802 -360.385868)
		(end 409.270962 -360.722926)
		(width 0.381)
		(layer "F.Cu")
		(net "GND")
	)
	(segment
		(start 89.194894 -284.311598)
		(end 89.194894 -284.847538)
		(width 0.2032)
		(layer "F.Cu")
		(net "GND")
	)
	(segment
		(start 123.387866 -230.622602)
		(end 123.387866 -230.086916)
		(width 0.254)
		(layer "F.Cu")
		(net "GND")
	)
	(segment
		(start 165.501066 -26.916888)
		(end 165.678866 -27.094688)
		(width 0.3556)
		(layer "F.Cu")
		(net "GND")
	)
	(segment
		(start 121.977912 -220.041978)
		(end 121.978166 -220.041724)
		(width 0.254)
		(layer "F.Cu")
		(net "GND")
	)
	(segment
		(start 30.771846 -199.01662)
		(end 31.876746 -199.01662)
		(width 0.381)
		(layer "F.Cu")
		(net "GND")
	)
	(segment
		(start 371.327934 -230.086916)
		(end 371.32768 -230.086662)
		(width 0.254)
		(layer "F.Cu")
		(net "GND")
	)
	(segment
		(start 374.727216 -270.167862)
		(end 374.727216 -270.19758)
		(width 0.2032)
		(layer "F.Cu")
		(net "GND")
	)
	(segment
		(start 188.988446 -317.166752)
		(end 190.093346 -317.166752)
		(width 0.381)
		(layer "F.Cu")
		(net "GND")
	)
	(segment
		(start 327.41489 -50.951384)
		(end 326.999854 -51.451764)
		(width 0.2032)
		(layer "F.Cu")
		(net "GND")
	)
	(segment
		(start 113.629694 -279.428194)
		(end 113.629694 -279.964134)
		(width 0.254)
		(layer "F.Cu")
		(net "GND")
	)
	(segment
		(start 411.958282 -288.317432)
		(end 411.907482 -288.266632)
		(width 0.381)
		(layer "F.Cu")
		(net "GND")
	)
	(segment
		(start 373.317516 -272.103342)
		(end 373.317516 -272.639282)
		(width 0.2032)
		(layer "F.Cu")
		(net "GND")
	)
	(segment
		(start 444.472314 -263.616694)
		(end 443.367414 -263.616694)
		(width 0.381)
		(layer "F.Cu")
		(net "GND")
	)
	(segment
		(start 135.245094 -259.894832)
		(end 135.24484 -260.430518)
		(width 0.254)
		(layer "F.Cu")
		(net "GND")
	)
	(segment
		(start 419.502082 -282.316682)
		(end 418.397182 -282.316682)
		(width 0.381)
		(layer "F.Cu")
		(net "GND")
	)
	(segment
		(start 307.566314 -206.666592)
		(end 308.887114 -206.666592)
		(width 0.381)
		(layer "F.Cu")
		(net "GND")
	)
	(segment
		(start 456.116182 -316.316614)
		(end 455.011282 -316.316614)
		(width 0.381)
		(layer "F.Cu")
		(net "GND")
	)
	(segment
		(start 63.726314 -282.316682)
		(end 65.047114 -282.316682)
		(width 0.381)
		(layer "F.Cu")
		(net "GND")
	)
	(segment
		(start 165.501066 -26.086562)
		(end 165.501066 -26.916888)
		(width 0.3556)
		(layer "F.Cu")
		(net "GND")
	)
	(segment
		(start 254.975614 -197.316598)
		(end 256.080514 -197.316598)
		(width 0.381)
		(layer "F.Cu")
		(net "GND")
	)
	(segment
		(start 124.437648 -259.093462)
		(end 124.437394 -259.616956)
		(width 0.2032)
		(layer "F.Cu")
		(net "GND")
	)
	(segment
		(start 355.461316 -271.011142)
		(end 355.461062 -271.011396)
		(width 0.2032)
		(layer "F.Cu")
		(net "GND")
	)
	(segment
		(start 193.088514 -202.416664)
		(end 191.983614 -202.416664)
		(width 0.381)
		(layer "F.Cu")
		(net "GND")
	)
	(segment
		(start 452.016114 -287.416748)
		(end 450.911214 -287.416748)
		(width 0.381)
		(layer "F.Cu")
		(net "GND")
	)
	(segment
		(start 85.795866 -217.06459)
		(end 85.795612 -217.064336)
		(width 0.2032)
		(layer "F.Cu")
		(net "GND")
	)
	(segment
		(start 353.00158 -216.250774)
		(end 353.001834 -216.25052)
		(width 0.254)
		(layer "F.Cu")
		(net "GND")
	)
	(segment
		(start 357.810562 -277.800562)
		(end 357.810562 -278.336502)
		(width 0.254)
		(layer "F.Cu")
		(net "GND")
	)
	(segment
		(start 117.278912 -220.041978)
		(end 117.279166 -220.041724)
		(width 0.254)
		(layer "F.Cu")
		(net "GND")
	)
	(segment
		(start 27.328114 -228.766624)
		(end 28.433014 -228.766624)
		(width 0.381)
		(layer "F.Cu")
		(net "GND")
	)
	(segment
		(start 413.192214 -250.016772)
		(end 414.297114 -250.016772)
		(width 0.381)
		(layer "F.Cu")
		(net "GND")
	)
	(segment
		(start 90.024712 -222.76181)
		(end 90.024966 -222.761556)
		(width 0.254)
		(layer "F.Cu")
		(net "GND")
	)
	(segment
		(start 194.193414 -258.516628)
		(end 193.088514 -258.516628)
		(width 0.381)
		(layer "F.Cu")
		(net "GND")
	)
	(segment
		(start 420.548308 -174.735236)
		(end 420.124128 -174.735236)
		(width 0.381)
		(layer "F.Cu")
		(net "GND")
	)
	(segment
		(start 102.444296 -358.452674)
		(end 101.833426 -358.452674)
		(width 0.381)
		(layer "F.Cu")
		(net "GND")
	)
	(segment
		(start 204.076046 -267.016738)
		(end 205.180946 -267.016738)
		(width 0.381)
		(layer "F.Cu")
		(net "GND")
	)
	(segment
		(start 183.353964 -335.483962)
		(end 184.369964 -335.483962)
		(width 0.508)
		(layer "F.Cu")
		(net "GND")
	)
	(segment
		(start 42.415714 -272.966688)
		(end 41.310814 -272.966688)
		(width 0.381)
		(layer "F.Cu")
		(net "GND")
	)
	(segment
		(start 369.448334 -214.344758)
		(end 369.448334 -213.732618)
		(width 0.254)
		(layer "F.Cu")
		(net "GND")
	)
	(segment
		(start 133.365748 -282.68422)
		(end 133.365748 -283.219906)
		(width 0.254)
		(layer "F.Cu")
		(net "GND")
	)
	(segment
		(start 29.13888 -426.792898)
		(end 29.77388 -426.792898)
		(width 0.3556)
		(layer "F.Cu")
		(net "GND")
	)
	(segment
		(start 117.581934 -107.931712)
		(end 118.216934 -107.931712)
		(width 0.3556)
		(layer "F.Cu")
		(net "GND")
	)
	(segment
		(start 106.471466 -227.367084)
		(end 106.471466 -226.831144)
		(width 0.2032)
		(layer "F.Cu")
		(net "GND")
	)
	(segment
		(start 158.813246 -296.766742)
		(end 159.918146 -296.766742)
		(width 0.381)
		(layer "F.Cu")
		(net "GND")
	)
	(segment
		(start 14.579346 -273.816572)
		(end 15.684246 -273.816572)
		(width 0.381)
		(layer "F.Cu")
		(net "GND")
	)
	(segment
		(start 294.302434 -423.05605)
		(end 294.302434 -423.56532)
		(width 0.3556)
		(layer "F.Cu")
		(net "GND")
	)
	(segment
		(start 343.60358 -220.041978)
		(end 343.603834 -220.041724)
		(width 0.254)
		(layer "F.Cu")
		(net "GND")
	)
	(segment
		(start 134.665466 -219.228162)
		(end 134.665466 -218.692222)
		(width 0.2032)
		(layer "F.Cu")
		(net "GND")
	)
	(segment
		(start 134.305294 -272.917158)
		(end 134.305548 -273.453098)
		(width 0.2032)
		(layer "F.Cu")
		(net "GND")
	)
	(segment
		(start 356.291134 -224.111566)
		(end 356.291134 -223.575626)
		(width 0.2032)
		(layer "F.Cu")
		(net "GND")
	)
	(segment
		(start 236.599984 -49.76495)
		(end 237.615984 -49.76495)
		(width 0.381)
		(layer "F.Cu")
		(net "GND")
	)
	(segment
		(start 411.958282 -239.81664)
		(end 410.853382 -239.81664)
		(width 0.381)
		(layer "F.Cu")
		(net "GND")
	)
	(segment
		(start 372.26748 -248.527824)
		(end 372.26748 -247.992138)
		(width 0.2032)
		(layer "F.Cu")
		(net "GND")
	)
	(segment
		(start 30.771846 -234.716574)
		(end 31.876746 -234.716574)
		(width 0.381)
		(layer "F.Cu")
		(net "GND")
	)
	(segment
		(start 361.569762 -253.383796)
		(end 361.569762 -253.919736)
		(width 0.254)
		(layer "F.Cu")
		(net "GND")
	)
	(segment
		(start 449.677282 -284.866588)
		(end 448.572382 -284.866588)
		(width 0.381)
		(layer "F.Cu")
		(net "GND")
	)
	(segment
		(start 97.653094 -258.802886)
		(end 97.653348 -258.80314)
		(width 0.2032)
		(layer "F.Cu")
		(net "GND")
	)
	(segment
		(start 386.83438 -224.925382)
		(end 386.83438 -224.389696)
		(width 0.2032)
		(layer "F.Cu")
		(net "GND")
	)
	(segment
		(start 346.532962 -269.66164)
		(end 346.532962 -270.19758)
		(width 0.2032)
		(layer "F.Cu")
		(net "GND")
	)
	(segment
		(start 403.846792 -11.26998)
		(end 403.846792 -10.16508)
		(width 0.3556)
		(layer "F.Cu")
		(net "GND")
	)
	(segment
		(start 183.45658 -413.41421)
		(end 183.45658 -412.5468)
		(width 0.3556)
		(layer "F.Cu")
		(net "GND")
	)
	(segment
		(start 293.799514 -238.966756)
		(end 292.694614 -238.966756)
		(width 0.381)
		(layer "F.Cu")
		(net "GND")
	)
	(segment
		(start 131.956048 -278.614378)
		(end 131.956048 -279.150318)
		(width 0.254)
		(layer "F.Cu")
		(net "GND")
	)
	(segment
		(start 33.037018 -165.154102)
		(end 32.591502 -165.599618)
		(width 0.381)
		(layer "F.Cu")
		(net "GND")
	)
	(segment
		(start 439.923682 -305.266598)
		(end 441.028582 -305.266598)
		(width 0.381)
		(layer "F.Cu")
		(net "GND")
	)
	(segment
		(start 364.71352 -63.82131)
		(end 363.58322 -63.82131)
		(width 0.3556)
		(layer "F.Cu")
		(net "GND")
	)
	(segment
		(start 304.338482 -213.46668)
		(end 305.443382 -213.46668)
		(width 0.381)
		(layer "F.Cu")
		(net "GND")
	)
	(segment
		(start 328.244962 -53.952902)
		(end 327.41489 -53.952902)
		(width 0.2032)
		(layer "F.Cu")
		(net "GND")
	)
	(segment
		(start 119.158512 -226.553268)
		(end 119.158512 -226.017582)
		(width 0.254)
		(layer "F.Cu")
		(net "GND")
	)
	(segment
		(start 296.794682 -222.816674)
		(end 297.899582 -222.816674)
		(width 0.381)
		(layer "F.Cu")
		(net "GND")
	)
	(segment
		(start 342.304116 -280.242264)
		(end 342.304116 -280.778204)
		(width 0.254)
		(layer "F.Cu")
		(net "GND")
	)
	(segment
		(start 367.208562 -279.428194)
		(end 367.208816 -279.964134)
		(width 0.254)
		(layer "F.Cu")
		(net "GND")
	)
	(segment
		(start 156.090874 -52.674012)
		(end 156.090874 -53.309012)
		(width 0.3556)
		(layer "F.Cu")
		(net "GND")
	)
	(segment
		(start 189.861952 -12.462002)
		(end 189.861698 -12.461748)
		(width 0.3556)
		(layer "F.Cu")
		(net "GND")
	)
	(segment
		(start 166.357046 -263.616694)
		(end 167.461946 -263.616694)
		(width 0.381)
		(layer "F.Cu")
		(net "GND")
	)
	(segment
		(start 89.084912 -247.178576)
		(end 89.085166 -247.178322)
		(width 0.2032)
		(layer "F.Cu")
		(net "GND")
	)
	(segment
		(start 384.485134 -235.506006)
		(end 384.485134 -234.97032)
		(width 0.2032)
		(layer "F.Cu")
		(net "GND")
	)
	(segment
		(start 196.329554 -77.06614)
		(end 196.329554 -78.40218)
		(width 0.3556)
		(layer "F.Cu")
		(net "GND")
	)
	(segment
		(start 99.388422 -414.376616)
		(end 98.60788 -414.376616)
		(width 0.3556)
		(layer "F.Cu")
		(net "GND")
	)
	(segment
		(start 330.252578 -47.040546)
		(end 329.980798 -46.570646)
		(width 0.254)
		(layer "F.Cu")
		(net "GND")
	)
	(segment
		(start 185.544714 -308.666642)
		(end 184.439814 -308.666642)
		(width 0.381)
		(layer "F.Cu")
		(net "GND")
	)
	(segment
		(start 65.047114 -310.366664)
		(end 66.367914 -310.366664)
		(width 0.381)
		(layer "F.Cu")
		(net "GND")
	)
	(segment
		(start 107.880912 -226.017582)
		(end 107.881166 -226.017328)
		(width 0.254)
		(layer "F.Cu")
		(net "GND")
	)
	(segment
		(start 18.54708 -11.26998)
		(end 18.54708 -12.37488)
		(width 0.3556)
		(layer "F.Cu")
		(net "GND")
	)
	(segment
		(start 113.519712 -229.808786)
		(end 113.519966 -229.808532)
		(width 0.2032)
		(layer "F.Cu")
		(net "GND")
	)
	(segment
		(start 211.619846 -278.066754)
		(end 212.724746 -278.066754)
		(width 0.381)
		(layer "F.Cu")
		(net "GND")
	)
	(segment
		(start 300.238414 -287.416748)
		(end 301.343314 -287.416748)
		(width 0.381)
		(layer "F.Cu")
		(net "GND")
	)
	(segment
		(start 344.183716 -279.150064)
		(end 344.183462 -279.150318)
		(width 0.254)
		(layer "F.Cu")
		(net "GND")
	)
	(segment
		(start 131.375912 -247.714262)
		(end 131.375912 -247.178322)
		(width 0.2032)
		(layer "F.Cu")
		(net "GND")
	)
	(segment
		(start 436.928514 -212.616796)
		(end 438.033414 -212.616796)
		(width 0.381)
		(layer "F.Cu")
		(net "GND")
	)
	(segment
		(start 427.045882 -306.96662)
		(end 425.940982 -306.96662)
		(width 0.381)
		(layer "F.Cu")
		(net "GND")
	)
	(segment
		(start 352.531934 -217.600276)
		(end 352.531934 -217.064336)
		(width 0.2032)
		(layer "F.Cu")
		(net "GND")
	)
	(segment
		(start 102.242112 -216.250774)
		(end 102.242366 -216.25052)
		(width 0.254)
		(layer "F.Cu")
		(net "GND")
	)
	(segment
		(start 348.882716 -254.197612)
		(end 348.882716 -254.733044)
		(width 0.2032)
		(layer "F.Cu")
		(net "GND")
	)
	(segment
		(start 137.154158 -253.943104)
		(end 137.13079 -253.919736)
		(width 0.2032)
		(layer "F.Cu")
		(net "GND")
	)
	(segment
		(start 356.761034 -220.041724)
		(end 356.761034 -219.506038)
		(width 0.254)
		(layer "F.Cu")
		(net "GND")
	)
	(segment
		(start 14.579346 -276.366732)
		(end 15.684246 -276.366732)
		(width 0.381)
		(layer "F.Cu")
		(net "GND")
	)
	(segment
		(start 456.116182 -264.466578)
		(end 455.011282 -264.466578)
		(width 0.381)
		(layer "F.Cu")
		(net "GND")
	)
	(segment
		(start 124.327412 -242.016788)
		(end 124.327412 -241.481102)
		(width 0.2032)
		(layer "F.Cu")
		(net "GND")
	)
	(segment
		(start 164.018214 -269.566644)
		(end 162.913314 -269.566644)
		(width 0.381)
		(layer "F.Cu")
		(net "GND")
	)
	(segment
		(start 112.579912 -223.297496)
		(end 112.579912 -222.76181)
		(width 0.254)
		(layer "F.Cu")
		(net "GND")
	)
	(segment
		(start 35.976814 -280.61666)
		(end 34.871914 -280.61666)
		(width 0.381)
		(layer "F.Cu")
		(net "GND")
	)
	(segment
		(start 94.364048 -270.475456)
		(end 94.364048 -271.011396)
		(width 0.2032)
		(layer "F.Cu")
		(net "GND")
	)
	(segment
		(start 193.088514 -284.866588)
		(end 194.193414 -284.866588)
		(width 0.381)
		(layer "F.Cu")
		(net "GND")
	)
	(segment
		(start 260.180582 -196.466714)
		(end 259.075682 -196.466714)
		(width 0.381)
		(layer "F.Cu")
		(net "GND")
	)
	(segment
		(start 42.057066 -10.16508)
		(end 42.057066 -11.26998)
		(width 0.3556)
		(layer "F.Cu")
		(net "GND")
	)
	(segment
		(start 282.811982 -222.816674)
		(end 283.916882 -222.816674)
		(width 0.381)
		(layer "F.Cu")
		(net "GND")
	)
	(segment
		(start 334.205834 -221.669864)
		(end 334.675734 -221.94774)
		(width 0.2032)
		(layer "F.Cu")
		(net "GND")
	)
	(segment
		(start 297.899582 -196.466714)
		(end 299.004482 -196.466714)
		(width 0.381)
		(layer "F.Cu")
		(net "GND")
	)
	(segment
		(start 464.764882 -301.01667)
		(end 463.659982 -301.01667)
		(width 0.381)
		(layer "F.Cu")
		(net "GND")
	)
	(segment
		(start 383.07518 -233.064304)
		(end 383.07518 -232.528618)
		(width 0.2032)
		(layer "F.Cu")
		(net "GND")
	)
	(segment
		(start 340.78418 -226.553268)
		(end 340.78418 -226.017582)
		(width 0.254)
		(layer "F.Cu")
		(net "GND")
	)
	(segment
		(start 300.238414 -251.716794)
		(end 301.343314 -251.716794)
		(width 0.381)
		(layer "F.Cu")
		(net "GND")
	)
	(segment
		(start 329.980036 -41.871646)
		(end 329.439778 -41.871646)
		(width 0.2032)
		(layer "F.Cu")
		(net "GND")
	)
	(segment
		(start 261.285482 -226.216718)
		(end 260.180582 -226.216718)
		(width 0.381)
		(layer "F.Cu")
		(net "GND")
	)
	(segment
		(start 358.102662 -269.20571)
		(end 358.280462 -269.38351)
		(width 0.254)
		(layer "F.Cu")
		(net "GND")
	)
	(segment
		(start 38.315646 -296.766742)
		(end 37.210746 -296.766742)
		(width 0.381)
		(layer "F.Cu")
		(net "GND")
	)
	(segment
		(start 12.240514 -280.61666)
		(end 13.345414 -280.61666)
		(width 0.381)
		(layer "F.Cu")
		(net "GND")
	)
	(segment
		(start 441.028582 -269.566644)
		(end 442.133482 -269.566644)
		(width 0.381)
		(layer "F.Cu")
		(net "GND")
	)
	(segment
		(start 100.472494 -259.894832)
		(end 100.472494 -260.430518)
		(width 0.254)
		(layer "F.Cu")
		(net "GND")
	)
	(segment
		(start 342.14181 -338.698332)
		(end 342.14181 -339.312504)
		(width 0.381)
		(layer "F.Cu")
		(net "GND")
	)
	(segment
		(start 448.572382 -278.916638)
		(end 449.677282 -278.916638)
		(width 0.381)
		(layer "F.Cu")
		(net "GND")
	)
	(segment
		(start 57.503314 -301.01667)
		(end 58.608214 -301.01667)
		(width 0.381)
		(layer "F.Cu")
		(net "GND")
	)
	(segment
		(start 14.579346 -199.01662)
		(end 15.684246 -199.01662)
		(width 0.381)
		(layer "F.Cu")
		(net "GND")
	)
	(segment
		(start 286.255714 -221.96679)
		(end 287.360614 -221.96679)
		(width 0.381)
		(layer "F.Cu")
		(net "GND")
	)
	(segment
		(start 19.784314 -241.516662)
		(end 20.889214 -241.516662)
		(width 0.381)
		(layer "F.Cu")
		(net "GND")
	)
	(segment
		(start 363.919516 -265.592306)
		(end 363.919262 -266.128246)
		(width 0.2032)
		(layer "F.Cu")
		(net "GND")
	)
	(segment
		(start 334.785716 -257.45313)
		(end 335.725262 -257.98907)
		(width 0.254)
		(layer "F.Cu")
		(net "GND")
	)
	(segment
		(start 348.882716 -264.500106)
		(end 348.882462 -264.50036)
		(width 0.254)
		(layer "F.Cu")
		(net "GND")
	)
	(segment
		(start 378.486162 -277.800562)
		(end 378.486162 -278.336502)
		(width 0.2032)
		(layer "F.Cu")
		(net "GND")
	)
	(segment
		(start 175.755554 -110.575344)
		(end 175.355504 -110.175294)
		(width 0.3556)
		(layer "F.Cu")
		(net "GND")
	)
	(segment
		(start 126.676912 -216.250774)
		(end 126.677166 -216.25052)
		(width 0.254)
		(layer "F.Cu")
		(net "GND")
	)
	(segment
		(start 29.666946 -300.166786)
		(end 30.771846 -300.166786)
		(width 0.381)
		(layer "F.Cu")
		(net "GND")
	)
	(segment
		(start 87.315294 -255.011682)
		(end 87.315294 -255.547622)
		(width 0.254)
		(layer "F.Cu")
		(net "GND")
	)
	(segment
		(start 178.9557 -111.375444)
		(end 179.35575 -110.975394)
		(width 0.3556)
		(layer "F.Cu")
		(net "GND")
	)
	(segment
		(start 405.648414 -220.266768)
		(end 406.753314 -220.266768)
		(width 0.381)
		(layer "F.Cu")
		(net "GND")
	)
	(segment
		(start 374.726962 -269.66164)
		(end 374.727216 -270.167862)
		(width 0.2032)
		(layer "F.Cu")
		(net "GND")
	)
	(segment
		(start 312.987182 -282.316682)
		(end 314.307982 -282.316682)
		(width 0.381)
		(layer "F.Cu")
		(net "GND")
	)
	(segment
		(start 279.816814 -307.816758)
		(end 278.711914 -307.816758)
		(width 0.381)
		(layer "F.Cu")
		(net "GND")
	)
	(segment
		(start 305.443382 -204.116686)
		(end 306.548282 -204.116686)
		(width 0.381)
		(layer "F.Cu")
		(net "GND")
	)
	(segment
		(start 52.298346 -250.016772)
		(end 53.403246 -250.016772)
		(width 0.381)
		(layer "F.Cu")
		(net "GND")
	)
	(segment
		(start 188.988446 -265.316716)
		(end 187.883546 -265.316716)
		(width 0.381)
		(layer "F.Cu")
		(net "GND")
	)
	(segment
		(start 383.54508 -237.133638)
		(end 383.54508 -236.597952)
		(width 0.254)
		(layer "F.Cu")
		(net "GND")
	)
	(segment
		(start 337.604862 -257.45313)
		(end 337.604862 -257.98907)
		(width 0.2032)
		(layer "F.Cu")
		(net "GND")
	)
	(segment
		(start 110.230666 -245.27256)
		(end 110.230666 -244.737128)
		(width 0.254)
		(layer "F.Cu")
		(net "GND")
	)
	(segment
		(start 294.904414 -307.816758)
		(end 293.799514 -307.816758)
		(width 0.381)
		(layer "F.Cu")
		(net "GND")
	)
	(segment
		(start 108.966762 -95.667068)
		(end 109.601762 -95.667068)
		(width 0.3556)
		(layer "F.Cu")
		(net "GND")
	)
	(segment
		(start 447.589402 -78.229968)
		(end 446.675002 -78.229968)
		(width 0.3556)
		(layer "F.Cu")
		(net "GND")
	)
	(segment
		(start 413.019748 -364.311184)
		(end 413.418274 -363.912658)
		(width 0.2032)
		(layer "F.Cu")
		(net "GND")
	)
	(segment
		(start 368.618516 -286.7533)
		(end 368.618516 -287.288986)
		(width 0.254)
		(layer "F.Cu")
		(net "GND")
	)
	(segment
		(start 434.4797 -175.597058)
		(end 433.83962 -175.597058)
		(width 0.254)
		(layer "F.Cu")
		(net "GND")
	)
	(segment
		(start 341.72398 -216.78646)
		(end 341.72398 -216.250774)
		(width 0.254)
		(layer "F.Cu")
		(net "GND")
	)
	(segment
		(start 406.753314 -315.46673)
		(end 405.648414 -315.46673)
		(width 0.381)
		(layer "F.Cu")
		(net "GND")
	)
	(segment
		(start 38.315646 -227.066602)
		(end 37.210746 -227.066602)
		(width 0.381)
		(layer "F.Cu")
		(net "GND")
	)
	(segment
		(start 130.906012 -246.900192)
		(end 130.906012 -246.364506)
		(width 0.2032)
		(layer "F.Cu")
		(net "GND")
	)
	(segment
		(start 341.918798 -43.751246)
		(end 341.37727 -44.691046)
		(width 0.2032)
		(layer "F.Cu")
		(net "GND")
	)
	(segment
		(start 350.762316 -286.7533)
		(end 350.762316 -287.288986)
		(width 0.254)
		(layer "F.Cu")
		(net "GND")
	)
	(segment
		(start 456.116182 -213.46668)
		(end 455.011282 -213.46668)
		(width 0.381)
		(layer "F.Cu")
		(net "GND")
	)
	(segment
		(start 164.22878 -310.366664)
		(end 162.913314 -310.366664)
		(width 0.381)
		(layer "F.Cu")
		(net "GND")
	)
	(segment
		(start 162.913314 -310.366664)
		(end 161.54527 -310.366664)
		(width 0.381)
		(layer "F.Cu")
		(net "GND")
	)
	(segment
		(start 365.799116 -280.242264)
		(end 365.799116 -280.778204)
		(width 0.254)
		(layer "F.Cu")
		(net "GND")
	)
	(segment
		(start 416.556952 -8.320024)
		(end 416.556952 -7.215124)
		(width 0.3556)
		(layer "F.Cu")
		(net "GND")
	)
	(segment
		(start 424.836082 -269.566644)
		(end 425.940982 -269.566644)
		(width 0.381)
		(layer "F.Cu")
		(net "GND")
	)
	(segment
		(start 100.832412 -233.877866)
		(end 100.832412 -233.34218)
		(width 0.2032)
		(layer "F.Cu")
		(net "GND")
	)
	(segment
		(start 45.859446 -278.066754)
		(end 46.964346 -278.066754)
		(width 0.381)
		(layer "F.Cu")
		(net "GND")
	)
	(segment
		(start 453.121014 -223.666558)
		(end 452.016114 -223.666558)
		(width 0.381)
		(layer "F.Cu")
		(net "GND")
	)
	(segment
		(start 301.844456 -14.506194)
		(end 301.93488 -14.41577)
		(width 0.3556)
		(layer "F.Cu")
		(net "GND")
	)
	(segment
		(start 108.45673 -61.102748)
		(end 109.06633 -61.102748)
		(width 0.3556)
		(layer "F.Cu")
		(net "GND")
	)
	(segment
		(start 293.799514 -306.116736)
		(end 292.694614 -306.116736)
		(width 0.381)
		(layer "F.Cu")
		(net "GND")
	)
	(segment
		(start 340.78418 -223.297496)
		(end 340.78418 -222.76181)
		(width 0.254)
		(layer "F.Cu")
		(net "GND")
	)
	(segment
		(start 376.49658 -226.017582)
		(end 376.496834 -226.017328)
		(width 0.254)
		(layer "F.Cu")
		(net "GND")
	)
	(segment
		(start 100.942648 -281.869896)
		(end 100.942394 -282.405836)
		(width 0.2032)
		(layer "F.Cu")
		(net "GND")
	)
	(segment
		(start 254.975614 -217.716608)
		(end 256.080514 -217.716608)
		(width 0.381)
		(layer "F.Cu")
		(net "GND")
	)
	(segment
		(start 444.472314 -289.11677)
		(end 445.577214 -289.11677)
		(width 0.381)
		(layer "F.Cu")
		(net "GND")
	)
	(segment
		(start 267.724382 -249.166634)
		(end 268.829282 -249.166634)
		(width 0.381)
		(layer "F.Cu")
		(net "GND")
	)
	(segment
		(start 91.544648 -275.35886)
		(end 91.544648 -275.894546)
		(width 0.2032)
		(layer "F.Cu")
		(net "GND")
	)
	(segment
		(start 359.58018 -226.017582)
		(end 359.580434 -226.017328)
		(width 0.254)
		(layer "F.Cu")
		(net "GND")
	)
	(segment
		(start 460.664814 -260.21665)
		(end 459.559914 -260.21665)
		(width 0.381)
		(layer "F.Cu")
		(net "GND")
	)
	(segment
		(start 436.928514 -234.716574)
		(end 438.033414 -234.716574)
		(width 0.381)
		(layer "F.Cu")
		(net "GND")
	)
	(segment
		(start 207.071214 -219.41663)
		(end 208.176114 -219.41663)
		(width 0.381)
		(layer "F.Cu")
		(net "GND")
	)
	(segment
		(start 214.615014 -262.76681)
		(end 215.719914 -262.76681)
		(width 0.381)
		(layer "F.Cu")
		(net "GND")
	)
	(segment
		(start 335.615534 -238.761524)
		(end 335.615534 -238.225584)
		(width 0.254)
		(layer "F.Cu")
		(net "GND")
	)
	(segment
		(start 293.799514 -307.816758)
		(end 292.694614 -307.816758)
		(width 0.381)
		(layer "F.Cu")
		(net "GND")
	)
	(segment
		(start 49.959514 -272.966688)
		(end 48.854614 -272.966688)
		(width 0.381)
		(layer "F.Cu")
		(net "GND")
	)
	(segment
		(start 126.786894 -269.66164)
		(end 126.787148 -270.167862)
		(width 0.2032)
		(layer "F.Cu")
		(net "GND")
	)
	(segment
		(start 184.439814 -269.566644)
		(end 185.544714 -269.566644)
		(width 0.381)
		(layer "F.Cu")
		(net "GND")
	)
	(segment
		(start 86.265766 -221.669864)
		(end 86.735666 -221.94774)
		(width 0.2032)
		(layer "F.Cu")
		(net "GND")
	)
	(segment
		(start 441.028582 -306.96662)
		(end 442.133482 -306.96662)
		(width 0.381)
		(layer "F.Cu")
		(net "GND")
	)
	(segment
		(start 375.55678 -239.57534)
		(end 375.557034 -239.575086)
		(width 0.2032)
		(layer "F.Cu")
		(net "GND")
	)
	(segment
		(start 29.666946 -227.066602)
		(end 30.771846 -227.066602)
		(width 0.381)
		(layer "F.Cu")
		(net "GND")
	)
	(segment
		(start 311.882282 -297.616626)
		(end 312.987182 -297.616626)
		(width 0.381)
		(layer "F.Cu")
		(net "GND")
	)
	(segment
		(start 193.088514 -230.466646)
		(end 194.193414 -230.466646)
		(width 0.381)
		(layer "F.Cu")
		(net "GND")
	)
	(segment
		(start 39.420546 -304.416714)
		(end 38.315646 -304.416714)
		(width 0.381)
		(layer "F.Cu")
		(net "GND")
	)
	(segment
		(start 211.619846 -272.116804)
		(end 212.724746 -272.116804)
		(width 0.381)
		(layer "F.Cu")
		(net "GND")
	)
	(segment
		(start 108.351066 -217.600276)
		(end 108.351066 -217.064336)
		(width 0.2032)
		(layer "F.Cu")
		(net "GND")
	)
	(segment
		(start 435.823614 -260.21665)
		(end 436.928514 -260.21665)
		(width 0.381)
		(layer "F.Cu")
		(net "GND")
	)
	(segment
		(start 65.047114 -205.816708)
		(end 66.152014 -205.816708)
		(width 0.381)
		(layer "F.Cu")
		(net "GND")
	)
	(segment
		(start 256.080514 -201.56678)
		(end 257.185414 -201.56678)
		(width 0.381)
		(layer "F.Cu")
		(net "GND")
	)
	(segment
		(start 376.02668 -245.272306)
		(end 376.02668 -244.73662)
		(width 0.2032)
		(layer "F.Cu")
		(net "GND")
	)
	(segment
		(start 120.726708 -15.526766)
		(end 121.47296 -15.526766)
		(width 0.3556)
		(layer "F.Cu")
		(net "GND")
	)
	(segment
		(start 207.071214 -267.866622)
		(end 208.176114 -267.866622)
		(width 0.381)
		(layer "F.Cu")
		(net "GND")
	)
	(segment
		(start 118.218966 -231.436164)
		(end 118.218966 -230.900478)
		(width 0.2032)
		(layer "F.Cu")
		(net "GND")
	)
	(segment
		(start 339.374734 -246.900446)
		(end 339.37448 -246.900192)
		(width 0.2032)
		(layer "F.Cu")
		(net "GND")
	)
	(segment
		(start 310.207914 -220.266768)
		(end 308.887114 -220.266768)
		(width 0.381)
		(layer "F.Cu")
		(net "GND")
	)
	(segment
		(start 144.74952 -76.451968)
		(end 144.720056 -76.481432)
		(width 0.3556)
		(layer "F.Cu")
		(net "GND")
	)
	(segment
		(start 90.494866 -235.506006)
		(end 90.494866 -234.970066)
		(width 0.2032)
		(layer "F.Cu")
		(net "GND")
	)
	(segment
		(start 26.223214 -250.866656)
		(end 27.328114 -250.866656)
		(width 0.381)
		(layer "F.Cu")
		(net "GND")
	)
	(segment
		(start 406.524714 -358.436926)
		(end 409.985464 -358.436926)
		(width 0.381)
		(layer "F.Cu")
		(net "GND")
	)
	(segment
		(start 306.615592 -207.658716)
		(end 306.473606 -207.51673)
		(width 0.381)
		(layer "F.Cu")
		(net "GND")
	)
	(segment
		(start 98.483166 -228.180646)
		(end 98.483166 -227.64496)
		(width 0.2032)
		(layer "F.Cu")
		(net "GND")
	)
	(segment
		(start 260.180582 -316.316614)
		(end 261.285482 -316.316614)
		(width 0.381)
		(layer "F.Cu")
		(net "GND")
	)
	(segment
		(start 375.55678 -237.947454)
		(end 375.55678 -237.411768)
		(width 0.254)
		(layer "F.Cu")
		(net "GND")
	)
	(segment
		(start 394.899896 -63.231776)
		(end 394.899642 -63.23203)
		(width 0.3556)
		(layer "F.Cu")
		(net "GND")
	)
	(segment
		(start 212.724746 -276.366732)
		(end 211.619846 -276.366732)
		(width 0.381)
		(layer "F.Cu")
		(net "GND")
	)
	(segment
		(start 332.263242 -39.403528)
		(end 332.397608 -39.443152)
		(width 0.2032)
		(layer "F.Cu")
		(net "GND")
	)
	(segment
		(start 300.238414 -227.066602)
		(end 301.343314 -227.066602)
		(width 0.381)
		(layer "F.Cu")
		(net "GND")
	)
	(segment
		(start 327.895458 -58.43524)
		(end 327.980548 -58.43524)
		(width 0.2032)
		(layer "F.Cu")
		(net "GND")
	)
	(segment
		(start 370.388134 -240.389156)
		(end 370.388134 -239.853216)
		(width 0.254)
		(layer "F.Cu")
		(net "GND")
	)
	(segment
		(start 343.13368 -240.388902)
		(end 343.13368 -239.853216)
		(width 0.2032)
		(layer "F.Cu")
		(net "GND")
	)
	(segment
		(start 207.071214 -222.816674)
		(end 208.176114 -222.816674)
		(width 0.381)
		(layer "F.Cu")
		(net "GND")
	)
	(segment
		(start 185.544714 -244.066568)
		(end 186.649614 -244.066568)
		(width 0.381)
		(layer "F.Cu")
		(net "GND")
	)
	(segment
		(start 418.397182 -241.516662)
		(end 417.292282 -241.516662)
		(width 0.381)
		(layer "F.Cu")
		(net "GND")
	)
	(segment
		(start 175.005746 -265.316716)
		(end 173.900846 -265.316716)
		(width 0.381)
		(layer "F.Cu")
		(net "GND")
	)
	(segment
		(start 179.194206 -30.880812)
		(end 179.194206 -30.33776)
		(width 0.17272)
		(layer "F.Cu")
		(net "GND")
	)
	(segment
		(start 104.504236 -40.935148)
		(end 104.504236 -41.570148)
		(width 0.3556)
		(layer "F.Cu")
		(net "GND")
	)
	(segment
		(start 301.343314 -208.366614)
		(end 302.664114 -208.366614)
		(width 0.381)
		(layer "F.Cu")
		(net "GND")
	)
	(segment
		(start 187.883546 -267.016738)
		(end 188.988446 -267.016738)
		(width 0.381)
		(layer "F.Cu")
		(net "GND")
	)
	(segment
		(start 254.975614 -270.416782)
		(end 256.080514 -270.416782)
		(width 0.381)
		(layer "F.Cu")
		(net "GND")
	)
	(segment
		(start 124.797312 -220.041978)
		(end 124.797566 -220.041724)
		(width 0.254)
		(layer "F.Cu")
		(net "GND")
	)
	(segment
		(start 185.544714 -295.916604)
		(end 184.439814 -295.916604)
		(width 0.381)
		(layer "F.Cu")
		(net "GND")
	)
	(segment
		(start 413.192214 -267.016738)
		(end 414.297114 -267.016738)
		(width 0.381)
		(layer "F.Cu")
		(net "GND")
	)
	(segment
		(start 60.947046 -227.066602)
		(end 62.051946 -227.066602)
		(width 0.381)
		(layer "F.Cu")
		(net "GND")
	)
	(segment
		(start 449.677282 -291.666676)
		(end 448.572382 -291.666676)
		(width 0.381)
		(layer "F.Cu")
		(net "GND")
	)
	(segment
		(start 118.218712 -233.064304)
		(end 118.218712 -232.528618)
		(width 0.254)
		(layer "F.Cu")
		(net "GND")
	)
	(segment
		(start 263.624314 -306.116736)
		(end 264.729214 -306.116736)
		(width 0.381)
		(layer "F.Cu")
		(net "GND")
	)
	(segment
		(start 117.76837 -338.328508)
		(end 117.76837 -337.955382)
		(width 0.381)
		(layer "F.Cu")
		(net "GND")
	)
	(segment
		(start 413.192214 -233.016806)
		(end 414.297114 -233.016806)
		(width 0.381)
		(layer "F.Cu")
		(net "GND")
	)
	(segment
		(start 357.087932 -385.17449)
		(end 356.4509 -385.17449)
		(width 0.3556)
		(layer "F.Cu")
		(net "GND")
	)
	(segment
		(start 260.180582 -306.96662)
		(end 259.075682 -306.96662)
		(width 0.381)
		(layer "F.Cu")
		(net "GND")
	)
	(segment
		(start 90.024712 -223.297496)
		(end 90.024712 -222.76181)
		(width 0.254)
		(layer "F.Cu")
		(net "GND")
	)
	(segment
		(start 42.415714 -249.166634)
		(end 41.310814 -249.166634)
		(width 0.381)
		(layer "F.Cu")
		(net "GND")
	)
	(segment
		(start 357.345234 -338.254848)
		(end 357.345234 -337.830668)
		(width 0.381)
		(layer "F.Cu")
		(net "GND")
	)
	(segment
		(start 275.436076 -420.544244)
		(end 275.436076 -421.05326)
		(width 0.3556)
		(layer "F.Cu")
		(net "GND")
	)
	(segment
		(start 207.071214 -250.866656)
		(end 208.176114 -250.866656)
		(width 0.381)
		(layer "F.Cu")
		(net "GND")
	)
	(segment
		(start 14.426946 -393.215876)
		(end 15.036546 -393.215876)
		(width 0.3556)
		(layer "F.Cu")
		(net "GND")
	)
	(segment
		(start 378.956316 -276.986492)
		(end 378.956316 -277.522432)
		(width 0.2032)
		(layer "F.Cu")
		(net "GND")
	)
	(segment
		(start 385.093464 -263.709404)
		(end 385.070604 -263.686544)
		(width 0.254)
		(layer "F.Cu")
		(net "GND")
	)
	(segment
		(start 134.775448 -283.497782)
		(end 134.775448 -284.033468)
		(width 0.254)
		(layer "F.Cu")
		(net "GND")
	)
	(segment
		(start 173.900846 -217.716608)
		(end 175.233584 -217.716608)
		(width 0.381)
		(layer "F.Cu")
		(net "GND")
	)
	(segment
		(start 348.30258 -242.830858)
		(end 348.30258 -242.295172)
		(width 0.254)
		(layer "F.Cu")
		(net "GND")
	)
	(segment
		(start 202.971146 -251.716794)
		(end 204.076046 -251.716794)
		(width 0.381)
		(layer "F.Cu")
		(net "GND")
	)
	(segment
		(start 425.940982 -258.516628)
		(end 427.045882 -258.516628)
		(width 0.381)
		(layer "F.Cu")
		(net "GND")
	)
	(segment
		(start 427.045882 -286.56661)
		(end 425.940982 -286.56661)
		(width 0.381)
		(layer "F.Cu")
		(net "GND")
	)
	(segment
		(start 181.444646 -258.516628)
		(end 182.549546 -258.516628)
		(width 0.381)
		(layer "F.Cu")
		(net "GND")
	)
	(segment
		(start 165.252146 -217.716608)
		(end 166.357046 -217.716608)
		(width 0.381)
		(layer "F.Cu")
		(net "GND")
	)
	(segment
		(start 127.726694 -279.428194)
		(end 127.726948 -279.964134)
		(width 0.2032)
		(layer "F.Cu")
		(net "GND")
	)
	(segment
		(start 202.971146 -233.016806)
		(end 204.076046 -233.016806)
		(width 0.381)
		(layer "F.Cu")
		(net "GND")
	)
	(segment
		(start 170.457114 -228.766624)
		(end 169.352214 -228.766624)
		(width 0.381)
		(layer "F.Cu")
		(net "GND")
	)
	(segment
		(start 181.444646 -261.916672)
		(end 182.549546 -261.916672)
		(width 0.381)
		(layer "F.Cu")
		(net "GND")
	)
	(segment
		(start 361.569762 -266.405868)
		(end 361.569762 -266.941808)
		(width 0.254)
		(layer "F.Cu")
		(net "GND")
	)
	(segment
		(start 441.028582 -247.466612)
		(end 442.133482 -247.466612)
		(width 0.381)
		(layer "F.Cu")
		(net "GND")
	)
	(segment
		(start 339.014562 -268.033754)
		(end 339.014816 -268.034008)
		(width 0.2032)
		(layer "F.Cu")
		(net "GND")
	)
	(segment
		(start 38.315646 -195.616576)
		(end 37.210746 -195.616576)
		(width 0.381)
		(layer "F.Cu")
		(net "GND")
	)
	(segment
		(start 357.087932 -386.41909)
		(end 356.4509 -386.41909)
		(width 0.3556)
		(layer "F.Cu")
		(net "GND")
	)
	(segment
		(start 414.297114 -295.06672)
		(end 415.402014 -295.06672)
		(width 0.381)
		(layer "F.Cu")
		(net "GND")
	)
	(segment
		(start 421.840914 -227.066602)
		(end 422.945814 -227.066602)
		(width 0.381)
		(layer "F.Cu")
		(net "GND")
	)
	(segment
		(start 342.304116 -275.35886)
		(end 342.304116 -275.8948)
		(width 0.2032)
		(layer "F.Cu")
		(net "GND")
	)
	(segment
		(start 26.223214 -230.466646)
		(end 27.328114 -230.466646)
		(width 0.381)
		(layer "F.Cu")
		(net "GND")
	)
	(segment
		(start 214.615014 -258.516628)
		(end 215.719914 -258.516628)
		(width 0.381)
		(layer "F.Cu")
		(net "GND")
	)
	(segment
		(start 414.297114 -301.866808)
		(end 415.402014 -301.866808)
		(width 0.381)
		(layer "F.Cu")
		(net "GND")
	)
	(segment
		(start 130.436366 -247.714008)
		(end 130.436366 -247.178322)
		(width 0.2032)
		(layer "F.Cu")
		(net "GND")
	)
	(segment
		(start 436.928514 -289.11677)
		(end 438.033414 -289.11677)
		(width 0.381)
		(layer "F.Cu")
		(net "GND")
	)
	(segment
		(start 97.804986 -414.35528)
		(end 97.821242 -414.371536)
		(width 0.3556)
		(layer "F.Cu")
		(net "GND")
	)
	(segment
		(start 181.444646 -283.166566)
		(end 180.339746 -283.166566)
		(width 0.381)
		(layer "F.Cu")
		(net "GND")
	)
	(segment
		(start 358.280716 -260.708902)
		(end 358.280716 -261.244588)
		(width 0.254)
		(layer "F.Cu")
		(net "GND")
	)
	(segment
		(start 7.035546 -195.616576)
		(end 8.140446 -195.616576)
		(width 0.381)
		(layer "F.Cu")
		(net "GND")
	)
	(segment
		(start 297.899582 -299.316648)
		(end 299.004482 -299.316648)
		(width 0.381)
		(layer "F.Cu")
		(net "GND")
	)
	(segment
		(start 126.518162 -337.173316)
		(end 126.518162 -336.741008)
		(width 0.2032)
		(layer "F.Cu")
		(net "GND")
	)
	(segment
		(start 302.85436 -430.25822)
		(end 302.85436 -429.621188)
		(width 0.3556)
		(layer "F.Cu")
		(net "GND")
	)
	(segment
		(start 11.135614 -303.566576)
		(end 12.240514 -303.566576)
		(width 0.381)
		(layer "F.Cu")
		(net "GND")
	)
	(segment
		(start 179.105814 -233.86669)
		(end 178.000914 -233.86669)
		(width 0.381)
		(layer "F.Cu")
		(net "GND")
	)
	(segment
		(start 14.445996 -106.506264)
		(end 14.445996 -107.083352)
		(width 0.3556)
		(layer "F.Cu")
		(net "GND")
	)
	(segment
		(start 384.124962 -272.917158)
		(end 384.594862 -272.639282)
		(width 0.254)
		(layer "F.Cu")
		(net "GND")
	)
	(segment
		(start 346.384626 -38.945566)
		(end 346.384626 -38.465252)
		(width 0.2032)
		(layer "F.Cu")
		(net "GND")
	)
	(segment
		(start 418.397182 -200.716642)
		(end 417.292282 -200.716642)
		(width 0.381)
		(layer "F.Cu")
		(net "GND")
	)
	(segment
		(start 162.913314 -230.466646)
		(end 164.018214 -230.466646)
		(width 0.381)
		(layer "F.Cu")
		(net "GND")
	)
	(segment
		(start 166.357046 -307.816758)
		(end 167.461946 -307.816758)
		(width 0.381)
		(layer "F.Cu")
		(net "GND")
	)
	(segment
		(start 197.637146 -289.11677)
		(end 196.532246 -289.11677)
		(width 0.381)
		(layer "F.Cu")
		(net "GND")
	)
	(segment
		(start 8.140446 -278.066754)
		(end 9.245346 -278.066754)
		(width 0.381)
		(layer "F.Cu")
		(net "GND")
	)
	(segment
		(start 261.285482 -278.916638)
		(end 260.180582 -278.916638)
		(width 0.381)
		(layer "F.Cu")
		(net "GND")
	)
	(segment
		(start 441.028582 -310.366664)
		(end 442.133482 -310.366664)
		(width 0.381)
		(layer "F.Cu")
		(net "GND")
	)
	(segment
		(start 262.519414 -263.616694)
		(end 263.624314 -263.616694)
		(width 0.381)
		(layer "F.Cu")
		(net "GND")
	)
	(segment
		(start 179.105814 -249.166634)
		(end 178.000914 -249.166634)
		(width 0.381)
		(layer "F.Cu")
		(net "GND")
	)
	(segment
		(start 304.338482 -258.516628)
		(end 305.443382 -258.516628)
		(width 0.381)
		(layer "F.Cu")
		(net "GND")
	)
	(segment
		(start 325.077836 -345.862656)
		(end 325.087234 -345.853258)
		(width 0.254)
		(layer "F.Cu")
		(net "GND")
	)
	(segment
		(start 363.919516 -279.150064)
		(end 363.919262 -279.150318)
		(width 0.254)
		(layer "F.Cu")
		(net "GND")
	)
	(segment
		(start 370.38788 -233.877866)
		(end 370.38788 -233.34218)
		(width 0.254)
		(layer "F.Cu")
		(net "GND")
	)
	(segment
		(start 179.105814 -247.466612)
		(end 178.000914 -247.466612)
		(width 0.381)
		(layer "F.Cu")
		(net "GND")
	)
	(segment
		(start 131.016248 -261.244588)
		(end 131.015994 -261.244842)
		(width 0.2032)
		(layer "F.Cu")
		(net "GND")
	)
	(segment
		(start 92.844112 -229.808786)
		(end 92.844366 -229.808532)
		(width 0.2032)
		(layer "F.Cu")
		(net "GND")
	)
	(segment
		(start 421.840914 -220.266768)
		(end 422.945814 -220.266768)
		(width 0.381)
		(layer "F.Cu")
		(net "GND")
	)
	(segment
		(start 266.619482 -284.866588)
		(end 267.724382 -284.866588)
		(width 0.381)
		(layer "F.Cu")
		(net "GND")
	)
	(segment
		(start 124.327412 -233.877866)
		(end 124.327412 -233.34218)
		(width 0.254)
		(layer "F.Cu")
		(net "GND")
	)
	(segment
		(start 366.15878 -229.808786)
		(end 366.159034 -229.808532)
		(width 0.254)
		(layer "F.Cu")
		(net "GND")
	)
	(segment
		(start 44.754546 -210.916774)
		(end 45.859446 -210.916774)
		(width 0.381)
		(layer "F.Cu")
		(net "GND")
	)
	(segment
		(start 281.707082 -211.766658)
		(end 282.811982 -211.766658)
		(width 0.381)
		(layer "F.Cu")
		(net "GND")
	)
	(segment
		(start 352.06178 -221.134178)
		(end 352.062034 -221.133924)
		(width 0.254)
		(layer "F.Cu")
		(net "GND")
	)
	(segment
		(start 38.315646 -289.11677)
		(end 37.210746 -289.11677)
		(width 0.381)
		(layer "F.Cu")
		(net "GND")
	)
	(segment
		(start 181.444646 -265.316716)
		(end 182.549546 -265.316716)
		(width 0.381)
		(layer "F.Cu")
		(net "GND")
	)
	(segment
		(start 459.559914 -201.56678)
		(end 458.455014 -201.56678)
		(width 0.381)
		(layer "F.Cu")
		(net "GND")
	)
	(segment
		(start 202.971146 -306.116736)
		(end 204.076046 -306.116736)
		(width 0.381)
		(layer "F.Cu")
		(net "GND")
	)
	(segment
		(start 368.50828 -228.994716)
		(end 368.50828 -228.45903)
		(width 0.254)
		(layer "F.Cu")
		(net "GND")
	)
	(segment
		(start 432.379882 -221.116652)
		(end 433.484782 -221.116652)
		(width 0.381)
		(layer "F.Cu")
		(net "GND")
	)
	(segment
		(start 301.343314 -233.016806)
		(end 302.448214 -233.016806)
		(width 0.381)
		(layer "F.Cu")
		(net "GND")
	)
	(segment
		(start 214.292688 -68.846446)
		(end 214.065358 -68.846446)
		(width 0.3556)
		(layer "F.Cu")
		(net "GND")
	)
	(segment
		(start 200.632314 -244.066568)
		(end 201.737214 -244.066568)
		(width 0.381)
		(layer "F.Cu")
		(net "GND")
	)
	(segment
		(start 44.754546 -195.616576)
		(end 45.859446 -195.616576)
		(width 0.381)
		(layer "F.Cu")
		(net "GND")
	)
	(segment
		(start 116.339112 -216.78646)
		(end 116.339112 -216.250774)
		(width 0.254)
		(layer "F.Cu")
		(net "GND")
	)
	(segment
		(start 347.36278 -234.156504)
		(end 347.363034 -234.15625)
		(width 0.254)
		(layer "F.Cu")
		(net "GND")
	)
	(segment
		(start 27.328114 -278.916638)
		(end 28.433014 -278.916638)
		(width 0.381)
		(layer "F.Cu")
		(net "GND")
	)
	(segment
		(start 296.794682 -297.616626)
		(end 297.899582 -297.616626)
		(width 0.381)
		(layer "F.Cu")
		(net "GND")
	)
	(segment
		(start 207.071214 -238.116618)
		(end 208.176114 -238.116618)
		(width 0.381)
		(layer "F.Cu")
		(net "GND")
	)
	(segment
		(start 12.240514 -250.866656)
		(end 13.345414 -250.866656)
		(width 0.381)
		(layer "F.Cu")
		(net "GND")
	)
	(segment
		(start 171.755562 -112.97539)
		(end 171.355512 -112.57534)
		(width 0.3556)
		(layer "F.Cu")
		(net "GND")
	)
	(segment
		(start 289.250882 -278.916638)
		(end 290.355782 -278.916638)
		(width 0.381)
		(layer "F.Cu")
		(net "GND")
	)
	(segment
		(start 176.896014 -277.216616)
		(end 178.000914 -277.216616)
		(width 0.381)
		(layer "F.Cu")
		(net "GND")
	)
	(segment
		(start 194.193414 -211.766658)
		(end 193.088514 -211.766658)
		(width 0.381)
		(layer "F.Cu")
		(net "GND")
	)
	(segment
		(start 331.608176 -55.028846)
		(end 331.067918 -55.028846)
		(width 0.2032)
		(layer "F.Cu")
		(net "GND")
	)
	(segment
		(start 261.285482 -222.816674)
		(end 260.180582 -222.816674)
		(width 0.381)
		(layer "F.Cu")
		(net "GND")
	)
	(segment
		(start 94.723966 -216.786206)
		(end 94.723966 -216.25052)
		(width 0.254)
		(layer "F.Cu")
		(net "GND")
	)
	(segment
		(start 46.488096 -393.315698)
		(end 47.21733 -393.315698)
		(width 0.4572)
		(layer "F.Cu")
		(net "GND")
	)
	(segment
		(start 89.555066 -228.459284)
		(end 89.554812 -228.45903)
		(width 0.2032)
		(layer "F.Cu")
		(net "GND")
	)
	(segment
		(start 304.338482 -224.516696)
		(end 305.443382 -224.516696)
		(width 0.381)
		(layer "F.Cu")
		(net "GND")
	)
	(segment
		(start 266.619482 -303.566576)
		(end 267.724382 -303.566576)
		(width 0.381)
		(layer "F.Cu")
		(net "GND")
	)
	(segment
		(start 40.39489 -397.82496)
		(end 40.413178 -397.806672)
		(width 0.4572)
		(layer "F.Cu")
		(net "GND")
	)
	(segment
		(start 12.240514 -222.816674)
		(end 13.345414 -222.816674)
		(width 0.381)
		(layer "F.Cu")
		(net "GND")
	)
	(segment
		(start 178.000914 -286.56661)
		(end 179.105814 -286.56661)
		(width 0.381)
		(layer "F.Cu")
		(net "GND")
	)
	(segment
		(start 363.929422 -387.119876)
		(end 364.438692 -387.119876)
		(width 0.3556)
		(layer "F.Cu")
		(net "GND")
	)
	(segment
		(start 339.37448 -242.016788)
		(end 339.37448 -241.481102)
		(width 0.2032)
		(layer "F.Cu")
		(net "GND")
	)
	(segment
		(start 436.928514 -272.116804)
		(end 438.033414 -272.116804)
		(width 0.381)
		(layer "F.Cu")
		(net "GND")
	)
	(segment
		(start 53.403246 -268.71676)
		(end 54.508146 -268.71676)
		(width 0.381)
		(layer "F.Cu")
		(net "GND")
	)
	(segment
		(start 345.48318 -234.69219)
		(end 345.483434 -234.691936)
		(width 0.254)
		(layer "F.Cu")
		(net "GND")
	)
	(segment
		(start 42.415714 -213.46668)
		(end 41.310814 -213.46668)
		(width 0.381)
		(layer "F.Cu")
		(net "GND")
	)
	(segment
		(start 294.904414 -214.316564)
		(end 293.799514 -214.316564)
		(width 0.381)
		(layer "F.Cu")
		(net "GND")
	)
	(segment
		(start 441.028582 -294.216582)
		(end 442.133482 -294.216582)
		(width 0.381)
		(layer "F.Cu")
		(net "GND")
	)
	(segment
		(start 60.947046 -220.266768)
		(end 62.267846 -220.266768)
		(width 0.381)
		(layer "F.Cu")
		(net "GND")
	)
	(segment
		(start 204.076046 -304.416714)
		(end 205.180946 -304.416714)
		(width 0.381)
		(layer "F.Cu")
		(net "GND")
	)
	(segment
		(start 200.632314 -284.866588)
		(end 201.737214 -284.866588)
		(width 0.381)
		(layer "F.Cu")
		(net "GND")
	)
	(segment
		(start 42.057066 -8.320024)
		(end 42.057066 -9.424924)
		(width 0.3556)
		(layer "F.Cu")
		(net "GND")
	)
	(segment
		(start 100.472494 -279.428194)
		(end 100.472494 -279.96388)
		(width 0.254)
		(layer "F.Cu")
		(net "GND")
	)
	(segment
		(start 92.954094 -255.011682)
		(end 92.954094 -255.547368)
		(width 0.2032)
		(layer "F.Cu")
		(net "GND")
	)
	(segment
		(start 214.0204 -121.2088)
		(end 213.741 -121.2088)
		(width 0.3556)
		(layer "F.Cu")
		(net "GND")
	)
	(segment
		(start 348.029022 -47.5361)
		(end 347.597222 -47.5361)
		(width 0.1524)
		(layer "F.Cu")
		(net "GND")
	)
	(segment
		(start 463.659982 -301.01667)
		(end 462.555082 -301.01667)
		(width 0.381)
		(layer "F.Cu")
		(net "GND")
	)
	(segment
		(start 30.771846 -212.616796)
		(end 31.876746 -212.616796)
		(width 0.381)
		(layer "F.Cu")
		(net "GND")
	)
	(segment
		(start 218.48953 -126.761748)
		(end 219.10548 -126.761748)
		(width 0.3556)
		(layer "F.Cu")
		(net "GND")
	)
	(segment
		(start 127.616712 -232.528618)
		(end 127.616966 -232.528364)
		(width 0.254)
		(layer "F.Cu")
		(net "GND")
	)
	(segment
		(start 409.748482 -267.866622)
		(end 410.853382 -267.866622)
		(width 0.381)
		(layer "F.Cu")
		(net "GND")
	)
	(segment
		(start 213.249256 -120.457214)
		(end 213.954614 -120.457214)
		(width 0.3556)
		(layer "F.Cu")
		(net "GND")
	)
	(segment
		(start 441.028582 -198.166736)
		(end 442.133482 -198.166736)
		(width 0.381)
		(layer "F.Cu")
		(net "GND")
	)
	(segment
		(start 428.279814 -258.516628)
		(end 429.384714 -258.516628)
		(width 0.381)
		(layer "F.Cu")
		(net "GND")
	)
	(segment
		(start 60.947046 -261.916672)
		(end 62.051946 -261.916672)
		(width 0.381)
		(layer "F.Cu")
		(net "GND")
	)
	(segment
		(start 372.73738 -226.017582)
		(end 372.737634 -226.017328)
		(width 0.254)
		(layer "F.Cu")
		(net "GND")
	)
	(segment
		(start 304.338482 -222.816674)
		(end 305.443382 -222.816674)
		(width 0.381)
		(layer "F.Cu")
		(net "GND")
	)
	(segment
		(start 132.425694 -261.522718)
		(end 132.425694 -262.058658)
		(width 0.2032)
		(layer "F.Cu")
		(net "GND")
	)
	(segment
		(start 308.013354 -434.76545)
		(end 308.013354 -435.27472)
		(width 0.3556)
		(layer "F.Cu")
		(net "GND")
	)
	(segment
		(start 199.527414 -284.866588)
		(end 200.632314 -284.866588)
		(width 0.381)
		(layer "F.Cu")
		(net "GND")
	)
	(segment
		(start 289.250882 -235.566712)
		(end 290.355782 -235.566712)
		(width 0.381)
		(layer "F.Cu")
		(net "GND")
	)
	(segment
		(start 17.658842 -105.937812)
		(end 17.658842 -106.910124)
		(width 0.3556)
		(layer "F.Cu")
		(net "GND")
	)
	(segment
		(start 439.923682 -301.01667)
		(end 441.028582 -301.01667)
		(width 0.381)
		(layer "F.Cu")
		(net "GND")
	)
	(segment
		(start 88.851232 -180.762656)
		(end 88.851232 -180.33873)
		(width 0.3556)
		(layer "F.Cu")
		(net "GND")
	)
	(segment
		(start 97.543112 -223.297496)
		(end 97.543112 -222.76181)
		(width 0.254)
		(layer "F.Cu")
		(net "GND")
	)
	(segment
		(start 372.377462 -264.500106)
		(end 372.377462 -264.50036)
		(width 0.2032)
		(layer "F.Cu")
		(net "GND")
	)
	(segment
		(start 311.882282 -202.416664)
		(end 312.987182 -202.416664)
		(width 0.381)
		(layer "F.Cu")
		(net "GND")
	)
	(segment
		(start 71.33717 -53.012086)
		(end 71.33717 -53.543708)
		(width 0.3556)
		(layer "F.Cu")
		(net "GND")
	)
	(segment
		(start 463.659982 -215.166702)
		(end 462.555082 -215.166702)
		(width 0.381)
		(layer "F.Cu")
		(net "GND")
	)
	(segment
		(start 120.678448 -287.288986)
		(end 120.678194 -287.28924)
		(width 0.254)
		(layer "F.Cu")
		(net "GND")
	)
	(segment
		(start 14.579346 -233.016806)
		(end 15.684246 -233.016806)
		(width 0.381)
		(layer "F.Cu")
		(net "GND")
	)
	(segment
		(start 344.653362 -285.939484)
		(end 344.653362 -286.475424)
		(width 0.2032)
		(layer "F.Cu")
		(net "GND")
	)
	(segment
		(start 46.964346 -317.166752)
		(end 45.859446 -317.166752)
		(width 0.381)
		(layer "F.Cu")
		(net "GND")
	)
	(segment
		(start 176.896014 -301.01667)
		(end 178.000914 -301.01667)
		(width 0.381)
		(layer "F.Cu")
		(net "GND")
	)
	(segment
		(start 96.133412 -237.133638)
		(end 96.133412 -236.597952)
		(width 0.2032)
		(layer "F.Cu")
		(net "GND")
	)
	(segment
		(start 38.315646 -233.016806)
		(end 37.210746 -233.016806)
		(width 0.381)
		(layer "F.Cu")
		(net "GND")
	)
	(segment
		(start 287.2994 -344.700352)
		(end 288.239708 -344.700352)
		(width 0.508)
		(layer "F.Cu")
		(net "GND")
	)
	(segment
		(start 188.988446 -231.316784)
		(end 187.883546 -231.316784)
		(width 0.381)
		(layer "F.Cu")
		(net "GND")
	)
	(segment
		(start 129.026412 -248.527824)
		(end 129.026412 -247.992138)
		(width 0.2032)
		(layer "F.Cu")
		(net "GND")
	)
	(segment
		(start 384.124962 -257.175254)
		(end 384.124962 -256.639314)
		(width 0.2032)
		(layer "F.Cu")
		(net "GND")
	)
	(segment
		(start 394.899642 -50.89525)
		(end 394.899896 -50.894996)
		(width 0.3556)
		(layer "F.Cu")
		(net "GND")
	)
	(segment
		(start 170.457114 -198.166736)
		(end 169.352214 -198.166736)
		(width 0.381)
		(layer "F.Cu")
		(net "GND")
	)
	(segment
		(start 173.900846 -276.366732)
		(end 175.005746 -276.366732)
		(width 0.381)
		(layer "F.Cu")
		(net "GND")
	)
	(segment
		(start 260.180582 -244.066568)
		(end 259.075682 -244.066568)
		(width 0.381)
		(layer "F.Cu")
		(net "GND")
	)
	(segment
		(start 460.664814 -195.616576)
		(end 459.559914 -195.616576)
		(width 0.381)
		(layer "F.Cu")
		(net "GND")
	)
	(segment
		(start 96.243648 -286.7533)
		(end 96.243648 -287.288986)
		(width 0.254)
		(layer "F.Cu")
		(net "GND")
	)
	(segment
		(start 379.896116 -278.614378)
		(end 379.896116 -279.150318)
		(width 0.254)
		(layer "F.Cu")
		(net "GND")
	)
	(segment
		(start 214.615014 -211.766658)
		(end 215.719914 -211.766658)
		(width 0.381)
		(layer "F.Cu")
		(net "GND")
	)
	(segment
		(start 282.811982 -230.466646)
		(end 283.916882 -230.466646)
		(width 0.381)
		(layer "F.Cu")
		(net "GND")
	)
	(segment
		(start 336.085434 -230.900478)
		(end 336.085434 -231.436418)
		(width 0.254)
		(layer "F.Cu")
		(net "GND")
	)
	(segment
		(start 394.84681 -8.320024)
		(end 394.84681 -9.424924)
		(width 0.3556)
		(layer "F.Cu")
		(net "GND")
	)
	(segment
		(start 271.168114 -231.316784)
		(end 270.063214 -231.316784)
		(width 0.381)
		(layer "F.Cu")
		(net "GND")
	)
	(segment
		(start 300.022514 -295.06672)
		(end 301.343314 -295.06672)
		(width 0.381)
		(layer "F.Cu")
		(net "GND")
	)
	(segment
		(start 411.907482 -288.266632)
		(end 410.853382 -288.266632)
		(width 0.381)
		(layer "F.Cu")
		(net "GND")
	)
	(segment
		(start 380.256034 -239.575086)
		(end 380.256034 -239.0394)
		(width 0.2032)
		(layer "F.Cu")
		(net "GND")
	)
	(segment
		(start 254.975614 -292.516814)
		(end 256.080514 -292.516814)
		(width 0.381)
		(layer "F.Cu")
		(net "GND")
	)
	(segment
		(start 325.077836 -346.763594)
		(end 325.077836 -345.862656)
		(width 0.3556)
		(layer "F.Cu")
		(net "GND")
	)
	(segment
		(start 7.495286 -101.125528)
		(end 7.495286 -100.691696)
		(width 0.3556)
		(layer "F.Cu")
		(net "GND")
	)
	(segment
		(start 45.859446 -248.31675)
		(end 46.964346 -248.31675)
		(width 0.381)
		(layer "F.Cu")
		(net "GND")
	)
	(segment
		(start 157.708346 -246.616728)
		(end 158.813246 -246.616728)
		(width 0.381)
		(layer "F.Cu")
		(net "GND")
	)
	(segment
		(start 350.376998 -334.191102)
		(end 349.97644 -333.790544)
		(width 0.2032)
		(layer "F.Cu")
		(net "GND")
	)
	(segment
		(start 462.555082 -198.166736)
		(end 463.659982 -198.166736)
		(width 0.381)
		(layer "F.Cu")
		(net "GND")
	)
	(segment
		(start 23.228046 -276.366732)
		(end 24.332946 -276.366732)
		(width 0.381)
		(layer "F.Cu")
		(net "GND")
	)
	(segment
		(start 60.947046 -309.51678)
		(end 62.051946 -309.51678)
		(width 0.381)
		(layer "F.Cu")
		(net "GND")
	)
	(segment
		(start 452.016114 -208.366614)
		(end 450.911214 -208.366614)
		(width 0.381)
		(layer "F.Cu")
		(net "GND")
	)
	(segment
		(start 271.168114 -307.816758)
		(end 270.063214 -307.816758)
		(width 0.381)
		(layer "F.Cu")
		(net "GND")
	)
	(segment
		(start 100.832412 -238.76127)
		(end 100.832412 -238.225584)
		(width 0.2032)
		(layer "F.Cu")
		(net "GND")
	)
	(segment
		(start 463.659982 -238.116618)
		(end 464.764882 -238.116618)
		(width 0.381)
		(layer "F.Cu")
		(net "GND")
	)
	(segment
		(start 9.90981 -97.784158)
		(end 9.29513 -97.784158)
		(width 0.3556)
		(layer "F.Cu")
		(net "GND")
	)
	(segment
		(start 169.022522 -418.479478)
		(end 168.412922 -418.479478)
		(width 0.381)
		(layer "F.Cu")
		(net "GND")
	)
	(segment
		(start 420.736014 -238.966756)
		(end 421.840914 -238.966756)
		(width 0.381)
		(layer "F.Cu")
		(net "GND")
	)
	(segment
		(start 274.163282 -222.816674)
		(end 275.268182 -222.816674)
		(width 0.381)
		(layer "F.Cu")
		(net "GND")
	)
	(segment
		(start 165.252146 -195.616576)
		(end 166.357046 -195.616576)
		(width 0.381)
		(layer "F.Cu")
		(net "GND")
	)
	(segment
		(start 345.593162 -279.428194)
		(end 345.593162 -279.96388)
		(width 0.254)
		(layer "F.Cu")
		(net "GND")
	)
	(segment
		(start 431.36693 -8.320024)
		(end 431.36693 -9.424924)
		(width 0.3556)
		(layer "F.Cu")
		(net "GND")
	)
	(segment
		(start 29.666946 -273.816572)
		(end 30.771846 -273.816572)
		(width 0.381)
		(layer "F.Cu")
		(net "GND")
	)
	(segment
		(start 372.377716 -279.150064)
		(end 372.377462 -279.150318)
		(width 0.254)
		(layer "F.Cu")
		(net "GND")
	)
	(segment
		(start 456.116182 -222.816674)
		(end 455.011282 -222.816674)
		(width 0.381)
		(layer "F.Cu")
		(net "GND")
	)
	(segment
		(start 373.207534 -217.600276)
		(end 373.207534 -217.064336)
		(width 0.254)
		(layer "F.Cu")
		(net "GND")
	)
	(segment
		(start 349.24238 -236.319822)
		(end 349.242634 -236.319568)
		(width 0.2032)
		(layer "F.Cu")
		(net "GND")
	)
	(segment
		(start 256.080514 -265.316716)
		(end 257.185414 -265.316716)
		(width 0.381)
		(layer "F.Cu")
		(net "GND")
	)
	(segment
		(start 312.987182 -277.216616)
		(end 314.092082 -277.216616)
		(width 0.381)
		(layer "F.Cu")
		(net "GND")
	)
	(segment
		(start 9.700006 -101.095302)
		(end 9.277096 -101.095302)
		(width 0.3556)
		(layer "F.Cu")
		(net "GND")
	)
	(segment
		(start 202.971146 -278.066754)
		(end 204.076046 -278.066754)
		(width 0.381)
		(layer "F.Cu")
		(net "GND")
	)
	(segment
		(start 42.415714 -308.666642)
		(end 41.310814 -308.666642)
		(width 0.381)
		(layer "F.Cu")
		(net "GND")
	)
	(segment
		(start 158.813246 -242.3668)
		(end 159.918146 -242.3668)
		(width 0.381)
		(layer "F.Cu")
		(net "GND")
	)
	(segment
		(start 96.138238 -414.35528)
		(end 97.804986 -414.35528)
		(width 0.3556)
		(layer "F.Cu")
		(net "GND")
	)
	(segment
		(start 103.40975 -361.334812)
		(end 103.40975 -361.944412)
		(width 0.381)
		(layer "F.Cu")
		(net "GND")
	)
	(segment
		(start 202.971146 -229.616762)
		(end 204.076046 -229.616762)
		(width 0.381)
		(layer "F.Cu")
		(net "GND")
	)
	(segment
		(start 405.648414 -306.116736)
		(end 406.753314 -306.116736)
		(width 0.381)
		(layer "F.Cu")
		(net "GND")
	)
	(segment
		(start 162.913314 -204.116686)
		(end 161.808414 -204.116686)
		(width 0.381)
		(layer "F.Cu")
		(net "GND")
	)
	(segment
		(start 22.123146 -268.71676)
		(end 23.228046 -268.71676)
		(width 0.381)
		(layer "F.Cu")
		(net "GND")
	)
	(segment
		(start 285.645352 -364.999016)
		(end 286.043878 -364.60049)
		(width 0.2032)
		(layer "F.Cu")
		(net "GND")
	)
	(segment
		(start 441.028582 -194.766692)
		(end 442.133482 -194.766692)
		(width 0.381)
		(layer "F.Cu")
		(net "GND")
	)
	(segment
		(start 167.461946 -223.666558)
		(end 166.357046 -223.666558)
		(width 0.381)
		(layer "F.Cu")
		(net "GND")
	)
	(segment
		(start 308.887114 -311.216802)
		(end 310.207914 -311.216802)
		(width 0.381)
		(layer "F.Cu")
		(net "GND")
	)
	(segment
		(start 130.076448 -267.755624)
		(end 130.076194 -267.755878)
		(width 0.254)
		(layer "F.Cu")
		(net "GND")
	)
	(segment
		(start 87.675466 -243.644928)
		(end 87.675466 -243.108988)
		(width 0.2032)
		(layer "F.Cu")
		(net "GND")
	)
	(segment
		(start 342.66378 -234.69219)
		(end 342.66378 -234.15625)
		(width 0.2032)
		(layer "F.Cu")
		(net "GND")
	)
	(segment
		(start 382.135634 -234.15625)
		(end 382.135634 -234.69219)
		(width 0.2032)
		(layer "F.Cu")
		(net "GND")
	)
	(segment
		(start 456.116182 -303.566576)
		(end 455.011282 -303.566576)
		(width 0.381)
		(layer "F.Cu")
		(net "GND")
	)
	(segment
		(start 275.268182 -295.916604)
		(end 274.163282 -295.916604)
		(width 0.381)
		(layer "F.Cu")
		(net "GND")
	)
	(segment
		(start 159.918146 -231.316784)
		(end 158.813246 -231.316784)
		(width 0.381)
		(layer "F.Cu")
		(net "GND")
	)
	(segment
		(start 170.457114 -232.166668)
		(end 171.562014 -232.166668)
		(width 0.381)
		(layer "F.Cu")
		(net "GND")
	)
	(segment
		(start 89.084912 -224.389696)
		(end 89.085166 -224.389442)
		(width 0.254)
		(layer "F.Cu")
		(net "GND")
	)
	(segment
		(start 211.99221 -26.468324)
		(end 211.149438 -26.468324)
		(width 0.3556)
		(layer "F.Cu")
		(net "GND")
	)
	(segment
		(start 362.039916 -273.730974)
		(end 362.039662 -274.266914)
		(width 0.254)
		(layer "F.Cu")
		(net "GND")
	)
	(segment
		(start 92.954094 -266.405868)
		(end 92.954348 -266.406122)
		(width 0.2032)
		(layer "F.Cu")
		(net "GND")
	)
	(segment
		(start 136.62533 -260.307836)
		(end 136.527032 -260.31063)
		(width 0.088646)
		(layer "F.Cu")
		(net "GND")
	)
	(segment
		(start 348.412562 -255.011682)
		(end 348.412562 -255.547368)
		(width 0.2032)
		(layer "F.Cu")
		(net "GND")
	)
	(segment
		(start 275.268182 -226.216718)
		(end 274.163282 -226.216718)
		(width 0.381)
		(layer "F.Cu")
		(net "GND")
	)
	(segment
		(start 301.133764 -15.552674)
		(end 301.154084 -15.572994)
		(width 0.3556)
		(layer "F.Cu")
		(net "GND")
	)
	(segment
		(start 164.018214 -288.317432)
		(end 164.232336 -288.317432)
		(width 0.381)
		(layer "F.Cu")
		(net "GND")
	)
	(segment
		(start 204.076046 -217.716608)
		(end 205.180946 -217.716608)
		(width 0.381)
		(layer "F.Cu")
		(net "GND")
	)
	(segment
		(start 341.276432 -42.649648)
		(end 341.36838 -42.808906)
		(width 0.2032)
		(layer "F.Cu")
		(net "GND")
	)
	(segment
		(start 353.581462 -277.522178)
		(end 353.581462 -277.522432)
		(width 0.2032)
		(layer "F.Cu")
		(net "GND")
	)
	(segment
		(start 349.822516 -280.77795)
		(end 349.822262 -280.778204)
		(width 0.2032)
		(layer "F.Cu")
		(net "GND")
	)
	(segment
		(start 102.242112 -222.76181)
		(end 102.242366 -222.761556)
		(width 0.254)
		(layer "F.Cu")
		(net "GND")
	)
	(segment
		(start 457.221082 -266.1666)
		(end 456.116182 -266.1666)
		(width 0.381)
		(layer "F.Cu")
		(net "GND")
	)
	(segment
		(start 170.457114 -213.46668)
		(end 169.352214 -213.46668)
		(width 0.381)
		(layer "F.Cu")
		(net "GND")
	)
	(segment
		(start 170.457114 -282.316682)
		(end 169.352214 -282.316682)
		(width 0.381)
		(layer "F.Cu")
		(net "GND")
	)
	(segment
		(start 92.954094 -268.033754)
		(end 92.954348 -268.034008)
		(width 0.2032)
		(layer "F.Cu")
		(net "GND")
	)
	(segment
		(start 386.97281 -269.73911)
		(end 387.481318 -270.247618)
		(width 0.254)
		(layer "F.Cu")
		(net "GND")
	)
	(segment
		(start 214.615014 -280.61666)
		(end 215.719914 -280.61666)
		(width 0.381)
		(layer "F.Cu")
		(net "GND")
	)
	(segment
		(start 92.844112 -247.714262)
		(end 92.844112 -247.178576)
		(width 0.2032)
		(layer "F.Cu")
		(net "GND")
	)
	(segment
		(start 130.076448 -262.336534)
		(end 130.076194 -262.872474)
		(width 0.2032)
		(layer "F.Cu")
		(net "GND")
	)
	(segment
		(start 344.073734 -240.389156)
		(end 344.07348 -240.388902)
		(width 0.2032)
		(layer "F.Cu")
		(net "GND")
	)
	(segment
		(start 262.519414 -273.816572)
		(end 263.624314 -273.816572)
		(width 0.381)
		(layer "F.Cu")
		(net "GND")
	)
	(segment
		(start 193.088514 -269.566644)
		(end 194.193414 -269.566644)
		(width 0.381)
		(layer "F.Cu")
		(net "GND")
	)
	(segment
		(start 132.785866 -242.017042)
		(end 132.785612 -242.016788)
		(width 0.2032)
		(layer "F.Cu")
		(net "GND")
	)
	(segment
		(start 435.823614 -289.11677)
		(end 436.928514 -289.11677)
		(width 0.381)
		(layer "F.Cu")
		(net "GND")
	)
	(segment
		(start 169.352214 -262.76681)
		(end 170.457114 -262.76681)
		(width 0.381)
		(layer "F.Cu")
		(net "GND")
	)
	(segment
		(start 425.940982 -278.916638)
		(end 424.836082 -278.916638)
		(width 0.381)
		(layer "F.Cu")
		(net "GND")
	)
	(segment
		(start 304.338482 -284.866588)
		(end 305.443382 -284.866588)
		(width 0.381)
		(layer "F.Cu")
		(net "GND")
	)
	(segment
		(start 63.726314 -238.116618)
		(end 65.047114 -238.116618)
		(width 0.381)
		(layer "F.Cu")
		(net "GND")
	)
	(segment
		(start 137.594594 -259.081016)
		(end 137.137902 -258.811268)
		(width 0.254)
		(layer "F.Cu")
		(net "GND")
	)
	(segment
		(start 300.238414 -258.516628)
		(end 301.343314 -258.516628)
		(width 0.381)
		(layer "F.Cu")
		(net "GND")
	)
	(segment
		(start 414.297114 -267.016738)
		(end 415.402014 -267.016738)
		(width 0.381)
		(layer "F.Cu")
		(net "GND")
	)
	(segment
		(start 420.93388 -157.032198)
		(end 420.93388 -157.648148)
		(width 0.3556)
		(layer "F.Cu")
		(net "GND")
	)
	(segment
		(start 136.545066 -230.622602)
		(end 136.545066 -230.086662)
		(width 0.254)
		(layer "F.Cu")
		(net "GND")
	)
	(segment
		(start 341.72398 -226.553268)
		(end 341.72398 -226.017582)
		(width 0.254)
		(layer "F.Cu")
		(net "GND")
	)
	(segment
		(start 335.615534 -237.133892)
		(end 335.615534 -236.597952)
		(width 0.254)
		(layer "F.Cu")
		(net "GND")
	)
	(segment
		(start 18.679414 -291.666676)
		(end 19.784314 -291.666676)
		(width 0.381)
		(layer "F.Cu")
		(net "GND")
	)
	(segment
		(start 278.711914 -261.916672)
		(end 279.816814 -261.916672)
		(width 0.381)
		(layer "F.Cu")
		(net "GND")
	)
	(segment
		(start 370.967762 -266.405868)
		(end 370.968016 -266.941808)
		(width 0.254)
		(layer "F.Cu")
		(net "GND")
	)
	(segment
		(start 349.712534 -243.644928)
		(end 349.71228 -243.644674)
		(width 0.254)
		(layer "F.Cu")
		(net "GND")
	)
	(segment
		(start 89.69883 -57.368948)
		(end 89.69883 -58.003948)
		(width 0.3556)
		(layer "F.Cu")
		(net "GND")
	)
	(segment
		(start 157.708346 -250.016772)
		(end 158.813246 -250.016772)
		(width 0.381)
		(layer "F.Cu")
		(net "GND")
	)
	(segment
		(start 134.195566 -220.041978)
		(end 134.195566 -219.506038)
		(width 0.254)
		(layer "F.Cu")
		(net "GND")
	)
	(segment
		(start 421.840914 -203.266802)
		(end 422.945814 -203.266802)
		(width 0.381)
		(layer "F.Cu")
		(net "GND")
	)
	(segment
		(start 366.66678 -335.541112)
		(end 367.019078 -335.541112)
		(width 0.2032)
		(layer "F.Cu")
		(net "GND")
	)
	(segment
		(start 45.859446 -307.816758)
		(end 46.964346 -307.816758)
		(width 0.381)
		(layer "F.Cu")
		(net "GND")
	)
	(segment
		(start 463.06359 -45.019722)
		(end 462.264506 -45.019722)
		(width 0.381)
		(layer "F.Cu")
		(net "GND")
	)
	(segment
		(start 464.764882 -314.616592)
		(end 463.659982 -314.616592)
		(width 0.381)
		(layer "F.Cu")
		(net "GND")
	)
	(segment
		(start 418.885878 -165.760654)
		(end 418.408866 -165.283642)
		(width 0.2032)
		(layer "F.Cu")
		(net "GND")
	)
	(segment
		(start 35.176968 -436.903368)
		(end 35.176968 -436.268368)
		(width 0.3556)
		(layer "F.Cu")
		(net "GND")
	)
	(segment
		(start 300.238414 -223.666558)
		(end 301.343314 -223.666558)
		(width 0.381)
		(layer "F.Cu")
		(net "GND")
	)
	(segment
		(start 282.811982 -205.816708)
		(end 283.916882 -205.816708)
		(width 0.381)
		(layer "F.Cu")
		(net "GND")
	)
	(segment
		(start 453.121014 -263.616694)
		(end 452.016114 -263.616694)
		(width 0.381)
		(layer "F.Cu")
		(net "GND")
	)
	(segment
		(start 278.711914 -272.116804)
		(end 279.816814 -272.116804)
		(width 0.381)
		(layer "F.Cu")
		(net "GND")
	)
	(segment
		(start 48.155606 -355.717602)
		(end 48.500284 -355.372924)
		(width 0.2032)
		(layer "F.Cu")
		(net "GND")
	)
	(segment
		(start 301.343314 -317.166752)
		(end 302.448214 -317.166752)
		(width 0.381)
		(layer "F.Cu")
		(net "GND")
	)
	(segment
		(start 304.338482 -250.866656)
		(end 305.443382 -250.866656)
		(width 0.381)
		(layer "F.Cu")
		(net "GND")
	)
	(segment
		(start 305.443382 -233.86669)
		(end 306.548282 -233.86669)
		(width 0.381)
		(layer "F.Cu")
		(net "GND")
	)
	(segment
		(start 333.510128 -54.558946)
		(end 333.23657 -54.089046)
		(width 0.2032)
		(layer "F.Cu")
		(net "GND")
	)
	(segment
		(start 57.503314 -266.1666)
		(end 58.608214 -266.1666)
		(width 0.381)
		(layer "F.Cu")
		(net "GND")
	)
	(segment
		(start 347.472762 -253.919482)
		(end 347.473016 -253.919736)
		(width 0.2032)
		(layer "F.Cu")
		(net "GND")
	)
	(segment
		(start 181.444646 -236.416596)
		(end 182.549546 -236.416596)
		(width 0.381)
		(layer "F.Cu")
		(net "GND")
	)
	(segment
		(start 290.355782 -247.466612)
		(end 291.460682 -247.466612)
		(width 0.381)
		(layer "F.Cu")
		(net "GND")
	)
	(segment
		(start 188.988446 -283.166566)
		(end 190.093346 -283.166566)
		(width 0.381)
		(layer "F.Cu")
		(net "GND")
	)
	(segment
		(start 162.938206 -235.591604)
		(end 164.183822 -235.591604)
		(width 0.381)
		(layer "F.Cu")
		(net "GND")
	)
	(segment
		(start 328.187812 -43.890946)
		(end 328.187812 -43.00474)
		(width 0.2032)
		(layer "F.Cu")
		(net "GND")
	)
	(segment
		(start 339.300058 -50.050446)
		(end 338.900008 -49.650396)
		(width 0.2032)
		(layer "F.Cu")
		(net "GND")
	)
	(segment
		(start 133.255512 -226.017582)
		(end 133.255766 -226.017328)
		(width 0.254)
		(layer "F.Cu")
		(net "GND")
	)
	(segment
		(start 349.24238 -231.436418)
		(end 349.242634 -231.436164)
		(width 0.2032)
		(layer "F.Cu")
		(net "GND")
	)
	(segment
		(start 39.420546 -231.316784)
		(end 38.315646 -231.316784)
		(width 0.381)
		(layer "F.Cu")
		(net "GND")
	)
	(segment
		(start 372.267734 -235.506006)
		(end 372.26748 -235.505752)
		(width 0.2032)
		(layer "F.Cu")
		(net "GND")
	)
	(segment
		(start 132.895848 -275.35886)
		(end 132.895594 -275.8948)
		(width 0.2032)
		(layer "F.Cu")
		(net "GND")
	)
	(segment
		(start 348.882716 -281.869896)
		(end 348.882462 -282.405836)
		(width 0.2032)
		(layer "F.Cu")
		(net "GND")
	)
	(segment
		(start 188.988446 -279.766776)
		(end 190.093346 -279.766776)
		(width 0.381)
		(layer "F.Cu")
		(net "GND")
	)
	(segment
		(start 34.871914 -297.616626)
		(end 33.767014 -297.616626)
		(width 0.381)
		(layer "F.Cu")
		(net "GND")
	)
	(segment
		(start 131.956048 -282.405582)
		(end 131.955794 -282.405836)
		(width 0.254)
		(layer "F.Cu")
		(net "GND")
	)
	(segment
		(start 361.65663 -407.228548)
		(end 362.37672 -407.228548)
		(width 0.3556)
		(layer "F.Cu")
		(net "GND")
	)
	(segment
		(start 171.562014 -297.616626)
		(end 170.457114 -297.616626)
		(width 0.381)
		(layer "F.Cu")
		(net "GND")
	)
	(segment
		(start 369.917726 -237.9472)
		(end 369.917726 -237.412022)
		(width 0.254)
		(layer "F.Cu")
		(net "GND")
	)
	(segment
		(start 190.093346 -208.366614)
		(end 188.988446 -208.366614)
		(width 0.381)
		(layer "F.Cu")
		(net "GND")
	)
	(segment
		(start 272.273014 -217.716608)
		(end 271.168114 -217.716608)
		(width 0.381)
		(layer "F.Cu")
		(net "GND")
	)
	(segment
		(start 131.846066 -250.155964)
		(end 131.846066 -249.620024)
		(width 0.2032)
		(layer "F.Cu")
		(net "GND")
	)
	(segment
		(start 358.170734 -237.133892)
		(end 358.170734 -236.597952)
		(width 0.2032)
		(layer "F.Cu")
		(net "GND")
	)
	(segment
		(start 308.887114 -317.166752)
		(end 309.992014 -317.166752)
		(width 0.381)
		(layer "F.Cu")
		(net "GND")
	)
	(segment
		(start 286.255714 -268.71676)
		(end 287.360614 -268.71676)
		(width 0.381)
		(layer "F.Cu")
		(net "GND")
	)
	(segment
		(start 444.472314 -212.616796)
		(end 443.367414 -212.616796)
		(width 0.381)
		(layer "F.Cu")
		(net "GND")
	)
	(segment
		(start 94.723966 -246.086376)
		(end 94.723966 -245.55069)
		(width 0.2032)
		(layer "F.Cu")
		(net "GND")
	)
	(segment
		(start 103.291894 -281.05608)
		(end 103.291894 -281.59202)
		(width 0.2032)
		(layer "F.Cu")
		(net "GND")
	)
	(segment
		(start 354.991162 -283.219652)
		(end 354.991416 -283.219906)
		(width 0.254)
		(layer "F.Cu")
		(net "GND")
	)
	(segment
		(start 374.481852 -339.296756)
		(end 374.827292 -338.951316)
		(width 0.2032)
		(layer "F.Cu")
		(net "GND")
	)
	(segment
		(start 448.572382 -267.866622)
		(end 447.467482 -267.866622)
		(width 0.381)
		(layer "F.Cu")
		(net "GND")
	)
	(segment
		(start 44.569634 -112.619282)
		(end 45.179234 -112.619282)
		(width 0.3556)
		(layer "F.Cu")
		(net "GND")
	)
	(segment
		(start 92.844112 -242.295172)
		(end 92.844366 -242.294918)
		(width 0.2032)
		(layer "F.Cu")
		(net "GND")
	)
	(segment
		(start 436.928514 -304.416714)
		(end 438.033414 -304.416714)
		(width 0.381)
		(layer "F.Cu")
		(net "GND")
	)
	(segment
		(start 432.379882 -216.866724)
		(end 433.484782 -216.866724)
		(width 0.381)
		(layer "F.Cu")
		(net "GND")
	)
	(segment
		(start 217.481912 -67.324478)
		(end 216.872312 -67.324478)
		(width 0.4572)
		(layer "F.Cu")
		(net "GND")
	)
	(segment
		(start 12.240514 -291.666676)
		(end 13.345414 -291.666676)
		(width 0.381)
		(layer "F.Cu")
		(net "GND")
	)
	(segment
		(start 452.016114 -306.116736)
		(end 450.911214 -306.116736)
		(width 0.381)
		(layer "F.Cu")
		(net "GND")
	)
	(segment
		(start 267.724382 -312.91657)
		(end 268.829282 -312.91657)
		(width 0.381)
		(layer "F.Cu")
		(net "GND")
	)
	(segment
		(start 345.15171 -52.59324)
		(end 345.554554 -51.95189)
		(width 0.1778)
		(layer "F.Cu")
		(net "GND")
	)
	(segment
		(start 118.218966 -229.808532)
		(end 118.218966 -229.272846)
		(width 0.254)
		(layer "F.Cu")
		(net "GND")
	)
	(segment
		(start 184.439814 -247.466612)
		(end 185.544714 -247.466612)
		(width 0.381)
		(layer "F.Cu")
		(net "GND")
	)
	(segment
		(start 462.555082 -210.066636)
		(end 463.659982 -210.066636)
		(width 0.381)
		(layer "F.Cu")
		(net "GND")
	)
	(segment
		(start 86.704424 -98.548952)
		(end 86.526116 -98.72726)
		(width 0.3556)
		(layer "F.Cu")
		(net "GND")
	)
	(segment
		(start 94.292674 -334.191102)
		(end 93.88856 -333.786988)
		(width 0.2032)
		(layer "F.Cu")
		(net "GND")
	)
	(segment
		(start 307.782214 -212.616796)
		(end 308.887114 -212.616796)
		(width 0.381)
		(layer "F.Cu")
		(net "GND")
	)
	(segment
		(start 341.921338 -53.148992)
		(end 342.193118 -53.618892)
		(width 0.2032)
		(layer "F.Cu")
		(net "GND")
	)
	(segment
		(start 343.821258 -42.341292)
		(end 343.81948 -42.341546)
		(width 0.254)
		(layer "F.Cu")
		(net "GND")
	)
	(segment
		(start 413.038798 -362.168186)
		(end 413.038798 -361.70235)
		(width 0.2032)
		(layer "F.Cu")
		(net "GND")
	)
	(segment
		(start 462.555082 -224.516696)
		(end 463.659982 -224.516696)
		(width 0.381)
		(layer "F.Cu")
		(net "GND")
	)
	(segment
		(start 376.606562 -285.939484)
		(end 376.606562 -286.475424)
		(width 0.2032)
		(layer "F.Cu")
		(net "GND")
	)
	(segment
		(start 94.833694 -277.800562)
		(end 94.833694 -278.336248)
		(width 0.2032)
		(layer "F.Cu")
		(net "GND")
	)
	(segment
		(start 384.015234 -244.458744)
		(end 384.015234 -243.922804)
		(width 0.254)
		(layer "F.Cu")
		(net "GND")
	)
	(segment
		(start 418.356796 -11.26998)
		(end 418.356796 -10.16508)
		(width 0.3556)
		(layer "F.Cu")
		(net "GND")
	)
	(segment
		(start 139.553188 -270.259556)
		(end 139.553188 -270.4719)
		(width 0.254)
		(layer "F.Cu")
		(net "GND")
	)
	(segment
		(start 96.603312 -226.553268)
		(end 96.603312 -226.017582)
		(width 0.254)
		(layer "F.Cu")
		(net "GND")
	)
	(segment
		(start 456.116182 -215.166702)
		(end 455.011282 -215.166702)
		(width 0.381)
		(layer "F.Cu")
		(net "GND")
	)
	(segment
		(start 281.707082 -232.166668)
		(end 282.811982 -232.166668)
		(width 0.381)
		(layer "F.Cu")
		(net "GND")
	)
	(segment
		(start 335.615534 -242.017042)
		(end 335.615534 -241.481102)
		(width 0.254)
		(layer "F.Cu")
		(net "GND")
	)
	(segment
		(start 199.527414 -194.766692)
		(end 200.632314 -194.766692)
		(width 0.381)
		(layer "F.Cu")
		(net "GND")
	)
	(segment
		(start 25.746964 -10.16508)
		(end 25.746964 -11.26998)
		(width 0.3556)
		(layer "F.Cu")
		(net "GND")
	)
	(segment
		(start 453.121014 -265.316716)
		(end 452.016114 -265.316716)
		(width 0.381)
		(layer "F.Cu")
		(net "GND")
	)
	(segment
		(start 452.016114 -289.11677)
		(end 450.911214 -289.11677)
		(width 0.381)
		(layer "F.Cu")
		(net "GND")
	)
	(segment
		(start 123.027694 -289.195002)
		(end 123.027694 -289.807142)
		(width 0.2032)
		(layer "F.Cu")
		(net "GND")
	)
	(segment
		(start 368.618516 -273.730974)
		(end 368.618262 -274.266914)
		(width 0.2032)
		(layer "F.Cu")
		(net "GND")
	)
	(segment
		(start 90.494866 -225.203512)
		(end 90.494612 -225.203258)
		(width 0.2032)
		(layer "F.Cu")
		(net "GND")
	)
	(segment
		(start 50.360834 -161.200592)
		(end 50.785014 -161.200592)
		(width 0.381)
		(layer "F.Cu")
		(net "GND")
	)
	(segment
		(start 358.96042 -416.824668)
		(end 359.245154 -416.539934)
		(width 0.3556)
		(layer "F.Cu")
		(net "GND")
	)
	(segment
		(start 56.182514 -238.116618)
		(end 57.503314 -238.116618)
		(width 0.381)
		(layer "F.Cu")
		(net "GND")
	)
	(segment
		(start 101.87178 -98.773996)
		(end 102.50678 -98.773996)
		(width 0.3556)
		(layer "F.Cu")
		(net "GND")
	)
	(segment
		(start 317.7921 -77.61986)
		(end 317.7921 -76.985114)
		(width 0.3556)
		(layer "F.Cu")
		(net "GND")
	)
	(segment
		(start 301.343314 -260.21665)
		(end 302.448214 -260.21665)
		(width 0.381)
		(layer "F.Cu")
		(net "GND")
	)
	(segment
		(start 338.90458 -249.342148)
		(end 338.904834 -249.341894)
		(width 0.2032)
		(layer "F.Cu")
		(net "GND")
	)
	(segment
		(start 380.25578 -223.297496)
		(end 380.25578 -222.76181)
		(width 0.254)
		(layer "F.Cu")
		(net "GND")
	)
	(segment
		(start 39.420546 -220.266768)
		(end 38.315646 -220.266768)
		(width 0.381)
		(layer "F.Cu")
		(net "GND")
	)
	(segment
		(start 182.549546 -287.416748)
		(end 181.444646 -287.416748)
		(width 0.381)
		(layer "F.Cu")
		(net "GND")
	)
	(segment
		(start 462.555082 -222.816674)
		(end 463.659982 -222.816674)
		(width 0.381)
		(layer "F.Cu")
		(net "GND")
	)
	(segment
		(start 129.496566 -246.086376)
		(end 129.496566 -245.55069)
		(width 0.2032)
		(layer "F.Cu")
		(net "GND")
	)
	(segment
		(start 202.971146 -208.366614)
		(end 204.076046 -208.366614)
		(width 0.381)
		(layer "F.Cu")
		(net "GND")
	)
	(segment
		(start 124.437648 -264.499852)
		(end 124.437394 -264.500106)
		(width 0.2032)
		(layer "F.Cu")
		(net "GND")
	)
	(segment
		(start 361.929934 -217.600276)
		(end 361.929934 -217.064336)
		(width 0.254)
		(layer "F.Cu")
		(net "GND")
	)
	(segment
		(start 377.43638 -229.808786)
		(end 377.43638 -229.272846)
		(width 0.2032)
		(layer "F.Cu")
		(net "GND")
	)
	(segment
		(start 38.315646 -214.316564)
		(end 37.210746 -214.316564)
		(width 0.381)
		(layer "F.Cu")
		(net "GND")
	)
	(segment
		(start 108.820712 -220.041978)
		(end 108.820966 -220.041724)
		(width 0.254)
		(layer "F.Cu")
		(net "GND")
	)
	(segment
		(start 20.889214 -211.766658)
		(end 19.784314 -211.766658)
		(width 0.381)
		(layer "F.Cu")
		(net "GND")
	)
	(segment
		(start 60.947046 -287.416748)
		(end 62.267846 -287.416748)
		(width 0.381)
		(layer "F.Cu")
		(net "GND")
	)
	(segment
		(start 209.35188 -108.822998)
		(end 208.71688 -108.822998)
		(width 0.3556)
		(layer "F.Cu")
		(net "GND")
	)
	(segment
		(start 122.447812 -238.76127)
		(end 122.447812 -238.225584)
		(width 0.2032)
		(layer "F.Cu")
		(net "GND")
	)
	(segment
		(start 131.375912 -226.553268)
		(end 131.375912 -226.017582)
		(width 0.254)
		(layer "F.Cu")
		(net "GND")
	)
	(segment
		(start 372.26748 -237.133638)
		(end 372.26748 -236.597952)
		(width 0.254)
		(layer "F.Cu")
		(net "GND")
	)
	(segment
		(start 48.962818 -359.08615)
		(end 48.962818 -358.991408)
		(width 0.381)
		(layer "F.Cu")
		(net "GND")
	)
	(segment
		(start 300.238414 -203.266802)
		(end 301.343314 -203.266802)
		(width 0.381)
		(layer "F.Cu")
		(net "GND")
	)
	(segment
		(start 411.958282 -275.516594)
		(end 410.853382 -275.516594)
		(width 0.381)
		(layer "F.Cu")
		(net "GND")
	)
	(segment
		(start 15.684246 -298.466764)
		(end 16.789146 -298.466764)
		(width 0.381)
		(layer "F.Cu")
		(net "GND")
	)
	(segment
		(start 387.77545 -34.581084)
		(end 387.77545 -35.589718)
		(width 0.3556)
		(layer "F.Cu")
		(net "GND")
	)
	(segment
		(start 99.422712 -233.064304)
		(end 99.422966 -233.06405)
		(width 0.254)
		(layer "F.Cu")
		(net "GND")
	)
	(segment
		(start 165.16096 -436.971948)
		(end 165.47592 -436.971948)
		(width 0.3556)
		(layer "F.Cu")
		(net "GND")
	)
	(segment
		(start 39.420546 -287.416748)
		(end 38.315646 -287.416748)
		(width 0.381)
		(layer "F.Cu")
		(net "GND")
	)
	(segment
		(start 190.093346 -236.416596)
		(end 188.988446 -236.416596)
		(width 0.381)
		(layer "F.Cu")
		(net "GND")
	)
	(segment
		(start 342.304116 -287.288986)
		(end 342.303862 -287.28924)
		(width 0.254)
		(layer "F.Cu")
		(net "GND")
	)
	(segment
		(start 170.457114 -267.866622)
		(end 171.562014 -267.866622)
		(width 0.381)
		(layer "F.Cu")
		(net "GND")
	)
	(segment
		(start 410.853382 -258.516628)
		(end 409.748482 -258.516628)
		(width 0.381)
		(layer "F.Cu")
		(net "GND")
	)
	(segment
		(start 361.45978 -247.178576)
		(end 361.460034 -247.178322)
		(width 0.254)
		(layer "F.Cu")
		(net "GND")
	)
	(segment
		(start 170.457114 -211.766658)
		(end 171.562014 -211.766658)
		(width 0.381)
		(layer "F.Cu")
		(net "GND")
	)
	(segment
		(start 423.121582 -362.562648)
		(end 422.72712 -362.168186)
		(width 0.2032)
		(layer "F.Cu")
		(net "GND")
	)
	(segment
		(start 236.599984 -245.011448)
		(end 236.599984 -244.368828)
		(width 0.381)
		(layer "F.Cu")
		(net "GND")
	)
	(segment
		(start 185.544714 -291.666676)
		(end 184.439814 -291.666676)
		(width 0.381)
		(layer "F.Cu")
		(net "GND")
	)
	(segment
		(start 179.105814 -235.566712)
		(end 178.000914 -235.566712)
		(width 0.381)
		(layer "F.Cu")
		(net "GND")
	)
	(segment
		(start 435.823614 -251.716794)
		(end 436.928514 -251.716794)
		(width 0.381)
		(layer "F.Cu")
		(net "GND")
	)
	(segment
		(start 19.784314 -310.366664)
		(end 20.889214 -310.366664)
		(width 0.381)
		(layer "F.Cu")
		(net "GND")
	)
	(segment
		(start 179.105814 -244.066568)
		(end 178.000914 -244.066568)
		(width 0.381)
		(layer "F.Cu")
		(net "GND")
	)
	(segment
		(start 331.608176 -40.931846)
		(end 331.067918 -40.931846)
		(width 0.2032)
		(layer "F.Cu")
		(net "GND")
	)
	(segment
		(start 137.484866 -246.900446)
		(end 137.484866 -246.364506)
		(width 0.254)
		(layer "F.Cu")
		(net "GND")
	)
	(segment
		(start 430.186592 -117.785896)
		(end 430.186592 -118.415054)
		(width 0.381)
		(layer "F.Cu")
		(net "GND")
	)
	(segment
		(start 63.942214 -196.466714)
		(end 65.047114 -196.466714)
		(width 0.381)
		(layer "F.Cu")
		(net "GND")
	)
	(segment
		(start 326.38746 -58.152284)
		(end 326.584818 -57.954926)
		(width 0.254)
		(layer "F.Cu")
		(net "GND")
	)
	(segment
		(start 108.45038 -402.628862)
		(end 108.45038 -402.200364)
		(width 0.3556)
		(layer "F.Cu")
		(net "GND")
	)
	(segment
		(start 267.724382 -280.61666)
		(end 268.829282 -280.61666)
		(width 0.381)
		(layer "F.Cu")
		(net "GND")
	)
	(segment
		(start 347.36278 -247.178576)
		(end 347.363034 -247.178322)
		(width 0.2032)
		(layer "F.Cu")
		(net "GND")
	)
	(segment
		(start 278.711914 -227.066602)
		(end 279.816814 -227.066602)
		(width 0.381)
		(layer "F.Cu")
		(net "GND")
	)
	(segment
		(start 134.80669 -345.055952)
		(end 134.633462 -345.474036)
		(width 0.1778)
		(layer "F.Cu")
		(net "GND")
	)
	(segment
		(start 428.279814 -265.316716)
		(end 429.384714 -265.316716)
		(width 0.381)
		(layer "F.Cu")
		(net "GND")
	)
	(segment
		(start 333.26578 -232.528364)
		(end 333.26578 -233.064304)
		(width 0.2032)
		(layer "F.Cu")
		(net "GND")
	)
	(segment
		(start 19.784314 -224.516696)
		(end 18.679414 -224.516696)
		(width 0.381)
		(layer "F.Cu")
		(net "GND")
	)
	(segment
		(start 43.520614 -301.01667)
		(end 42.415714 -301.01667)
		(width 0.381)
		(layer "F.Cu")
		(net "GND")
	)
	(segment
		(start 289.250882 -271.266666)
		(end 290.355782 -271.266666)
		(width 0.381)
		(layer "F.Cu")
		(net "GND")
	)
	(segment
		(start 202.971146 -242.3668)
		(end 204.076046 -242.3668)
		(width 0.381)
		(layer "F.Cu")
		(net "GND")
	)
	(segment
		(start 462.555082 -232.166668)
		(end 463.659982 -232.166668)
		(width 0.381)
		(layer "F.Cu")
		(net "GND")
	)
	(segment
		(start 101.772466 -246.36476)
		(end 101.772212 -246.364506)
		(width 0.2032)
		(layer "F.Cu")
		(net "GND")
	)
	(segment
		(start 12.240514 -288.266632)
		(end 13.345414 -288.266632)
		(width 0.381)
		(layer "F.Cu")
		(net "GND")
	)
	(segment
		(start 128.666494 -281.05608)
		(end 128.666748 -281.59202)
		(width 0.2032)
		(layer "F.Cu")
		(net "GND")
	)
	(segment
		(start 59.842146 -304.416714)
		(end 60.947046 -304.416714)
		(width 0.381)
		(layer "F.Cu")
		(net "GND")
	)
	(segment
		(start 23.760938 -175.83404)
		(end 23.760938 -174.93488)
		(width 0.254)
		(layer "F.Cu")
		(net "GND")
	)
	(segment
		(start 337.49488 -245.272306)
		(end 337.49488 -244.73662)
		(width 0.2032)
		(layer "F.Cu")
		(net "GND")
	)
	(segment
		(start 110.918752 -335.541112)
		(end 110.639098 -335.541112)
		(width 0.1778)
		(layer "F.Cu")
		(net "GND")
	)
	(segment
		(start 191.651382 -435.169056)
		(end 191.816482 -435.003956)
		(width 0.3556)
		(layer "F.Cu")
		(net "GND")
	)
	(segment
		(start 124.437648 -255.825498)
		(end 124.437648 -256.361184)
		(width 0.254)
		(layer "F.Cu")
		(net "GND")
	)
	(segment
		(start 346.384626 -56.95442)
		(end 346.799662 -57.454546)
		(width 0.2032)
		(layer "F.Cu")
		(net "GND")
	)
	(segment
		(start 358.280716 -255.825498)
		(end 358.280716 -256.361184)
		(width 0.254)
		(layer "F.Cu")
		(net "GND")
	)
	(segment
		(start 22.123146 -201.56678)
		(end 23.228046 -201.56678)
		(width 0.381)
		(layer "F.Cu")
		(net "GND")
	)
	(segment
		(start 180.4924 -94.738698)
		(end 179.2224 -94.738698)
		(width 0.3556)
		(layer "F.Cu")
		(net "GND")
	)
	(segment
		(start 84.626196 -93.538294)
		(end 83.991196 -93.538294)
		(width 0.3556)
		(layer "F.Cu")
		(net "GND")
	)
	(segment
		(start 60.947046 -203.266802)
		(end 62.051946 -203.266802)
		(width 0.381)
		(layer "F.Cu")
		(net "GND")
	)
	(segment
		(start 364.389162 -284.311598)
		(end 364.389162 -284.847284)
		(width 0.254)
		(layer "F.Cu")
		(net "GND")
	)
	(segment
		(start 135.14705 -17.655032)
		(end 135.14705 -16.550132)
		(width 0.3556)
		(layer "F.Cu")
		(net "GND")
	)
	(segment
		(start 383.655062 -280.242264)
		(end 383.655062 -280.778204)
		(width 0.254)
		(layer "F.Cu")
		(net "GND")
	)
	(segment
		(start 19.784314 -316.316614)
		(end 20.889214 -316.316614)
		(width 0.381)
		(layer "F.Cu")
		(net "GND")
	)
	(segment
		(start 93.893894 -255.011682)
		(end 93.893894 -255.547368)
		(width 0.2032)
		(layer "F.Cu")
		(net "GND")
	)
	(segment
		(start 342.90254 -38.465252)
		(end 342.90254 -39.295324)
		(width 0.2032)
		(layer "F.Cu")
		(net "GND")
	)
	(segment
		(start 413.192214 -229.616762)
		(end 414.297114 -229.616762)
		(width 0.381)
		(layer "F.Cu")
		(net "GND")
	)
	(segment
		(start 194.193414 -224.516696)
		(end 193.088514 -224.516696)
		(width 0.381)
		(layer "F.Cu")
		(net "GND")
	)
	(segment
		(start 261.285482 -261.066788)
		(end 260.180582 -261.066788)
		(width 0.381)
		(layer "F.Cu")
		(net "GND")
	)
	(segment
		(start 174.403512 -419.674548)
		(end 175.038512 -419.674548)
		(width 0.3556)
		(layer "F.Cu")
		(net "GND")
	)
	(segment
		(start 324.98919 -26.774648)
		(end 324.793864 -26.579322)
		(width 0.3556)
		(layer "F.Cu")
		(net "GND")
	)
	(segment
		(start 107.051094 -275.080476)
		(end 107.051348 -275.08073)
		(width 0.254)
		(layer "F.Cu")
		(net "GND")
	)
	(segment
		(start 18.679414 -230.466646)
		(end 19.784314 -230.466646)
		(width 0.381)
		(layer "F.Cu")
		(net "GND")
	)
	(segment
		(start 23.228046 -270.416782)
		(end 24.332946 -270.416782)
		(width 0.381)
		(layer "F.Cu")
		(net "GND")
	)
	(segment
		(start 178.000914 -232.166668)
		(end 176.896014 -232.166668)
		(width 0.381)
		(layer "F.Cu")
		(net "GND")
	)
	(segment
		(start 181.444646 -201.56678)
		(end 182.549546 -201.56678)
		(width 0.381)
		(layer "F.Cu")
		(net "GND")
	)
	(segment
		(start 282.811982 -271.266666)
		(end 283.916882 -271.266666)
		(width 0.381)
		(layer "F.Cu")
		(net "GND")
	)
	(segment
		(start 137.594594 -260.708902)
		(end 137.256012 -260.630162)
		(width 0.254)
		(layer "F.Cu")
		(net "GND")
	)
	(segment
		(start 59.842146 -242.3668)
		(end 60.947046 -242.3668)
		(width 0.381)
		(layer "F.Cu")
		(net "GND")
	)
	(segment
		(start 267.724382 -266.1666)
		(end 268.829282 -266.1666)
		(width 0.381)
		(layer "F.Cu")
		(net "GND")
	)
	(segment
		(start 162.913314 -241.516662)
		(end 161.808414 -241.516662)
		(width 0.381)
		(layer "F.Cu")
		(net "GND")
	)
	(segment
		(start 137.635488 -348.061026)
		(end 136.909048 -348.061026)
		(width 0.3556)
		(layer "F.Cu")
		(net "GND")
	)
	(segment
		(start 199.527414 -262.76681)
		(end 200.632314 -262.76681)
		(width 0.381)
		(layer "F.Cu")
		(net "GND")
	)
	(segment
		(start 343.006934 -55.028592)
		(end 343.005156 -55.028846)
		(width 0.2032)
		(layer "F.Cu")
		(net "GND")
	)
	(segment
		(start 352.171762 -271.289272)
		(end 352.172016 -271.289526)
		(width 0.2032)
		(layer "F.Cu")
		(net "GND")
	)
	(segment
		(start 357.340662 -265.592306)
		(end 357.340662 -266.127992)
		(width 0.254)
		(layer "F.Cu")
		(net "GND")
	)
	(segment
		(start 456.116182 -278.916638)
		(end 455.011282 -278.916638)
		(width 0.381)
		(layer "F.Cu")
		(net "GND")
	)
	(segment
		(start 207.071214 -288.266632)
		(end 208.176114 -288.266632)
		(width 0.381)
		(layer "F.Cu")
		(net "GND")
	)
	(segment
		(start 357.810562 -266.405868)
		(end 357.810562 -266.941808)
		(width 0.254)
		(layer "F.Cu")
		(net "GND")
	)
	(segment
		(start 358.640634 -220.041978)
		(end 358.640634 -219.506038)
		(width 0.254)
		(layer "F.Cu")
		(net "GND")
	)
	(segment
		(start 65.047114 -258.516628)
		(end 66.152014 -258.516628)
		(width 0.381)
		(layer "F.Cu")
		(net "GND")
	)
	(segment
		(start 101.412548 -271.289526)
		(end 101.412548 -271.825212)
		(width 0.2032)
		(layer "F.Cu")
		(net "GND")
	)
	(segment
		(start 196.532246 -304.416714)
		(end 195.427346 -304.416714)
		(width 0.381)
		(layer "F.Cu")
		(net "GND")
	)
	(segment
		(start 419.502082 -196.466714)
		(end 418.397182 -196.466714)
		(width 0.381)
		(layer "F.Cu")
		(net "GND")
	)
	(segment
		(start 281.707082 -239.81664)
		(end 282.811982 -239.81664)
		(width 0.381)
		(layer "F.Cu")
		(net "GND")
	)
	(segment
		(start 56.398414 -303.566576)
		(end 57.503314 -303.566576)
		(width 0.381)
		(layer "F.Cu")
		(net "GND")
	)
	(segment
		(start 381.305816 -281.591766)
		(end 381.305816 -281.59202)
		(width 0.254)
		(layer "F.Cu")
		(net "GND")
	)
	(segment
		(start 185.544714 -316.316614)
		(end 184.439814 -316.316614)
		(width 0.381)
		(layer "F.Cu")
		(net "GND")
	)
	(segment
		(start 381.775716 -281.869896)
		(end 381.775716 -282.405582)
		(width 0.254)
		(layer "F.Cu")
		(net "GND")
	)
	(segment
		(start 114.459766 -220.041978)
		(end 114.459766 -219.506038)
		(width 0.254)
		(layer "F.Cu")
		(net "GND")
	)
	(segment
		(start 244.37467 -251.581158)
		(end 244.75694 -251.198888)
		(width 0.3556)
		(layer "F.Cu")
		(net "GND")
	)
	(segment
		(start 132.315712 -220.041978)
		(end 132.315712 -219.506292)
		(width 0.254)
		(layer "F.Cu")
		(net "GND")
	)
	(segment
		(start 398.446752 -11.26998)
		(end 398.446752 -10.16508)
		(width 0.3556)
		(layer "F.Cu")
		(net "GND")
	)
	(segment
		(start 441.028582 -216.866724)
		(end 442.133482 -216.866724)
		(width 0.381)
		(layer "F.Cu")
		(net "GND")
	)
	(segment
		(start 368.508534 -228.99497)
		(end 368.50828 -228.994716)
		(width 0.254)
		(layer "F.Cu")
		(net "GND")
	)
	(segment
		(start 128.666494 -255.547368)
		(end 128.666748 -255.547622)
		(width 0.2032)
		(layer "F.Cu")
		(net "GND")
	)
	(segment
		(start 179.105814 -202.416664)
		(end 178.000914 -202.416664)
		(width 0.381)
		(layer "F.Cu")
		(net "GND")
	)
	(segment
		(start 332.796134 -237.133892)
		(end 332.32598 -237.411768)
		(width 0.2032)
		(layer "F.Cu")
		(net "GND")
	)
	(segment
		(start 45.859446 -195.616576)
		(end 46.964346 -195.616576)
		(width 0.381)
		(layer "F.Cu")
		(net "GND")
	)
	(segment
		(start 51.467004 -12.37488)
		(end 51.467004 -11.26998)
		(width 0.3556)
		(layer "F.Cu")
		(net "GND")
	)
	(segment
		(start 208.176114 -306.96662)
		(end 209.281014 -306.96662)
		(width 0.381)
		(layer "F.Cu")
		(net "GND")
	)
	(segment
		(start 459.559914 -272.116804)
		(end 460.664814 -272.116804)
		(width 0.381)
		(layer "F.Cu")
		(net "GND")
	)
	(segment
		(start 307.782214 -246.616728)
		(end 308.887114 -246.616728)
		(width 0.381)
		(layer "F.Cu")
		(net "GND")
	)
	(segment
		(start 272.273014 -201.56678)
		(end 271.168114 -201.56678)
		(width 0.381)
		(layer "F.Cu")
		(net "GND")
	)
	(segment
		(start 256.080514 -300.166786)
		(end 257.185414 -300.166786)
		(width 0.381)
		(layer "F.Cu")
		(net "GND")
	)
	(segment
		(start 449.677282 -262.76681)
		(end 448.572382 -262.76681)
		(width 0.381)
		(layer "F.Cu")
		(net "GND")
	)
	(segment
		(start 337.604862 -270.475456)
		(end 337.604862 -271.011396)
		(width 0.2032)
		(layer "F.Cu")
		(net "GND")
	)
	(segment
		(start 85.795866 -245.27256)
		(end 86.260178 -245.540276)
		(width 0.2032)
		(layer "F.Cu")
		(net "GND")
	)
	(segment
		(start 173.900846 -210.916774)
		(end 172.795946 -210.916774)
		(width 0.381)
		(layer "F.Cu")
		(net "GND")
	)
	(segment
		(start 211.619846 -244.916706)
		(end 212.724746 -244.916706)
		(width 0.381)
		(layer "F.Cu")
		(net "GND")
	)
	(segment
		(start 48.854614 -228.766624)
		(end 49.959514 -228.766624)
		(width 0.381)
		(layer "F.Cu")
		(net "GND")
	)
	(segment
		(start 370.967762 -282.683966)
		(end 370.968016 -282.68422)
		(width 0.254)
		(layer "F.Cu")
		(net "GND")
	)
	(segment
		(start 77.984096 -343.391998)
		(end 77.55509 -342.962992)
		(width 0.2032)
		(layer "F.Cu")
		(net "GND")
	)
	(segment
		(start 42.415714 -221.116652)
		(end 41.310814 -221.116652)
		(width 0.381)
		(layer "F.Cu")
		(net "GND")
	)
	(segment
		(start 58.666888 -11.26998)
		(end 58.666888 -12.37488)
		(width 0.3556)
		(layer "F.Cu")
		(net "GND")
	)
	(segment
		(start 93.16085 -33.061148)
		(end 93.16085 -32.426148)
		(width 0.3556)
		(layer "F.Cu")
		(net "GND")
	)
	(segment
		(start 77.493876 -347.881448)
		(end 77.982826 -347.881448)
		(width 0.381)
		(layer "F.Cu")
		(net "GND")
	)
	(segment
		(start 291.460682 -226.216718)
		(end 290.355782 -226.216718)
		(width 0.381)
		(layer "F.Cu")
		(net "GND")
	)
	(segment
		(start 464.764882 -310.366664)
		(end 463.659982 -310.366664)
		(width 0.381)
		(layer "F.Cu")
		(net "GND")
	)
	(segment
		(start 15.684246 -267.016738)
		(end 16.789146 -267.016738)
		(width 0.381)
		(layer "F.Cu")
		(net "GND")
	)
	(segment
		(start 462.555082 -264.466578)
		(end 463.659982 -264.466578)
		(width 0.381)
		(layer "F.Cu")
		(net "GND")
	)
	(segment
		(start 366.738916 -270.475456)
		(end 366.738662 -271.011396)
		(width 0.254)
		(layer "F.Cu")
		(net "GND")
	)
	(segment
		(start 35.976814 -299.316648)
		(end 34.871914 -299.316648)
		(width 0.381)
		(layer "F.Cu")
		(net "GND")
	)
	(segment
		(start 18.95729 -393.45362)
		(end 19.119596 -393.615926)
		(width 0.254)
		(layer "F.Cu")
		(net "GND")
	)
	(segment
		(start 126.317248 -256.361184)
		(end 126.316994 -256.361438)
		(width 0.254)
		(layer "F.Cu")
		(net "GND")
	)
	(segment
		(start 422.273984 -364.963964)
		(end 422.750996 -364.486952)
		(width 0.2032)
		(layer "F.Cu")
		(net "GND")
	)
	(segment
		(start 460.664814 -225.36658)
		(end 459.559914 -225.36658)
		(width 0.381)
		(layer "F.Cu")
		(net "GND")
	)
	(segment
		(start 350.762316 -280.242264)
		(end 350.762316 -280.778204)
		(width 0.2032)
		(layer "F.Cu")
		(net "GND")
	)
	(segment
		(start 65.047114 -262.76681)
		(end 66.152014 -262.76681)
		(width 0.381)
		(layer "F.Cu")
		(net "GND")
	)
	(segment
		(start 125.377448 -287.288986)
		(end 125.377194 -287.28924)
		(width 0.254)
		(layer "F.Cu")
		(net "GND")
	)
	(segment
		(start 14.579346 -272.116804)
		(end 15.684246 -272.116804)
		(width 0.381)
		(layer "F.Cu")
		(net "GND")
	)
	(segment
		(start 347.36278 -233.064304)
		(end 347.363034 -233.06405)
		(width 0.254)
		(layer "F.Cu")
		(net "GND")
	)
	(segment
		(start 210.14563 -126.512828)
		(end 210.75523 -126.512828)
		(width 0.3556)
		(layer "F.Cu")
		(net "GND")
	)
	(segment
		(start 128.556512 -220.041978)
		(end 128.556766 -220.041724)
		(width 0.254)
		(layer "F.Cu")
		(net "GND")
	)
	(segment
		(start 346.42298 -220.041978)
		(end 346.423234 -220.041724)
		(width 0.254)
		(layer "F.Cu")
		(net "GND")
	)
	(segment
		(start 372.847362 -285.939484)
		(end 372.847362 -286.475424)
		(width 0.2032)
		(layer "F.Cu")
		(net "GND")
	)
	(segment
		(start 344.63355 -49.390046)
		(end 344.363294 -48.919892)
		(width 0.254)
		(layer "F.Cu")
		(net "GND")
	)
	(segment
		(start 208.176114 -277.216616)
		(end 209.281014 -277.216616)
		(width 0.381)
		(layer "F.Cu")
		(net "GND")
	)
	(segment
		(start 429.384714 -201.56678)
		(end 430.489614 -201.56678)
		(width 0.381)
		(layer "F.Cu")
		(net "GND")
	)
	(segment
		(start 308.887114 -307.816758)
		(end 309.992014 -307.816758)
		(width 0.381)
		(layer "F.Cu")
		(net "GND")
	)
	(segment
		(start 164.298376 -205.816708)
		(end 162.913314 -205.816708)
		(width 0.381)
		(layer "F.Cu")
		(net "GND")
	)
	(segment
		(start 384.124962 -276.172676)
		(end 384.124962 -276.708616)
		(width 0.254)
		(layer "F.Cu")
		(net "GND")
	)
	(segment
		(start 344.183462 -263.964674)
		(end 344.183462 -264.50036)
		(width 0.254)
		(layer "F.Cu")
		(net "GND")
	)
	(segment
		(start 119.738648 -288.381186)
		(end 119.738648 -288.917126)
		(width 0.254)
		(layer "F.Cu")
		(net "GND")
	)
	(segment
		(start 92.844112 -237.947454)
		(end 92.844366 -237.947454)
		(width 0.254)
		(layer "F.Cu")
		(net "GND")
	)
	(segment
		(start 361.569762 -272.917158)
		(end 361.569762 -273.453098)
		(width 0.254)
		(layer "F.Cu")
		(net "GND")
	)
	(segment
		(start 429.384714 -220.266768)
		(end 430.489614 -220.266768)
		(width 0.381)
		(layer "F.Cu")
		(net "GND")
	)
	(segment
		(start 136.075166 -234.15625)
		(end 136.075166 -234.69219)
		(width 0.2032)
		(layer "F.Cu")
		(net "GND")
	)
	(segment
		(start 123.036584 -40.351456)
		(end 123.036584 -40.986456)
		(width 0.3556)
		(layer "F.Cu")
		(net "GND")
	)
	(segment
		(start 212.724746 -281.466798)
		(end 211.619846 -281.466798)
		(width 0.381)
		(layer "F.Cu")
		(net "GND")
	)
	(segment
		(start 164.66566 -436.893208)
		(end 165.08222 -436.893208)
		(width 0.3556)
		(layer "F.Cu")
		(net "GND")
	)
	(segment
		(start 285.150814 -278.066754)
		(end 286.255714 -278.066754)
		(width 0.381)
		(layer "F.Cu")
		(net "GND")
	)
	(segment
		(start 272.273014 -242.3668)
		(end 271.168114 -242.3668)
		(width 0.381)
		(layer "F.Cu")
		(net "GND")
	)
	(segment
		(start 130.906266 -230.622602)
		(end 130.906012 -230.622348)
		(width 0.2032)
		(layer "F.Cu")
		(net "GND")
	)
	(segment
		(start 354.991162 -281.591766)
		(end 354.991416 -281.59202)
		(width 0.254)
		(layer "F.Cu")
		(net "GND")
	)
	(segment
		(start 7.035546 -281.466798)
		(end 8.140446 -281.466798)
		(width 0.381)
		(layer "F.Cu")
		(net "GND")
	)
	(segment
		(start 122.558048 -286.7533)
		(end 122.558048 -287.288986)
		(width 0.254)
		(layer "F.Cu")
		(net "GND")
	)
	(segment
		(start 421.840914 -214.316564)
		(end 422.945814 -214.316564)
		(width 0.381)
		(layer "F.Cu")
		(net "GND")
	)
	(segment
		(start 138.424666 -245.27256)
		(end 139.229084 -245.27256)
		(width 0.2032)
		(layer "F.Cu")
		(net "GND")
	)
	(segment
		(start 385.064762 -279.428194)
		(end 385.064762 -279.964134)
		(width 0.2032)
		(layer "F.Cu")
		(net "GND")
	)
	(segment
		(start 65.047114 -266.1666)
		(end 66.152014 -266.1666)
		(width 0.381)
		(layer "F.Cu")
		(net "GND")
	)
	(segment
		(start 271.168114 -309.51678)
		(end 270.063214 -309.51678)
		(width 0.381)
		(layer "F.Cu")
		(net "GND")
	)
	(segment
		(start 282.811982 -224.516696)
		(end 283.916882 -224.516696)
		(width 0.381)
		(layer "F.Cu")
		(net "GND")
	)
	(segment
		(start 193.088514 -245.76659)
		(end 191.983614 -245.76659)
		(width 0.381)
		(layer "F.Cu")
		(net "GND")
	)
	(segment
		(start 332.012798 -58.020204)
		(end 332.397608 -58.020204)
		(width 0.2032)
		(layer "F.Cu")
		(net "GND")
	)
	(segment
		(start 276.373082 -305.266598)
		(end 275.268182 -305.266598)
		(width 0.381)
		(layer "F.Cu")
		(net "GND")
	)
	(segment
		(start 307.782214 -251.716794)
		(end 308.887114 -251.716794)
		(width 0.381)
		(layer "F.Cu")
		(net "GND")
	)
	(segment
		(start 410.853382 -316.316614)
		(end 409.748482 -316.316614)
		(width 0.381)
		(layer "F.Cu")
		(net "GND")
	)
	(segment
		(start 375.557034 -239.575086)
		(end 375.557034 -239.0394)
		(width 0.2032)
		(layer "F.Cu")
		(net "GND")
	)
	(segment
		(start 328.625708 -50.329846)
		(end 328.244962 -49.950878)
		(width 0.1778)
		(layer "F.Cu")
		(net "GND")
	)
	(segment
		(start 12.240514 -211.766658)
		(end 13.345414 -211.766658)
		(width 0.381)
		(layer "F.Cu")
		(net "GND")
	)
	(segment
		(start 361.45978 -222.76181)
		(end 361.460034 -222.761556)
		(width 0.254)
		(layer "F.Cu")
		(net "GND")
	)
	(segment
		(start 92.844112 -226.017582)
		(end 92.844366 -226.017328)
		(width 0.254)
		(layer "F.Cu")
		(net "GND")
	)
	(segment
		(start 414.297114 -289.11677)
		(end 415.402014 -289.11677)
		(width 0.381)
		(layer "F.Cu")
		(net "GND")
	)
	(segment
		(start 443.367414 -244.916706)
		(end 444.472314 -244.916706)
		(width 0.381)
		(layer "F.Cu")
		(net "GND")
	)
	(segment
		(start 441.028582 -196.466714)
		(end 442.133482 -196.466714)
		(width 0.381)
		(layer "F.Cu")
		(net "GND")
	)
	(segment
		(start 254.975614 -195.616576)
		(end 256.080514 -195.616576)
		(width 0.381)
		(layer "F.Cu")
		(net "GND")
	)
	(segment
		(start 348.772734 -232.250488)
		(end 348.772734 -231.714548)
		(width 0.2032)
		(layer "F.Cu")
		(net "GND")
	)
	(segment
		(start 296.794682 -207.51673)
		(end 297.899582 -207.51673)
		(width 0.381)
		(layer "F.Cu")
		(net "GND")
	)
	(segment
		(start 196.532246 -244.916706)
		(end 197.637146 -244.916706)
		(width 0.381)
		(layer "F.Cu")
		(net "GND")
	)
	(segment
		(start 12.240514 -202.416664)
		(end 13.345414 -202.416664)
		(width 0.381)
		(layer "F.Cu")
		(net "GND")
	)
	(segment
		(start 402.046948 -8.320024)
		(end 402.046948 -7.215124)
		(width 0.3556)
		(layer "F.Cu")
		(net "GND")
	)
	(segment
		(start 115.039648 -277.522178)
		(end 115.039394 -277.522432)
		(width 0.254)
		(layer "F.Cu")
		(net "GND")
	)
	(segment
		(start 76.105512 -39.675562)
		(end 76.105512 -40.310562)
		(width 0.3556)
		(layer "F.Cu")
		(net "GND")
	)
	(segment
		(start 158.813246 -295.06672)
		(end 159.952436 -295.06672)
		(width 0.381)
		(layer "F.Cu")
		(net "GND")
	)
	(segment
		(start 195.427346 -267.016738)
		(end 196.532246 -267.016738)
		(width 0.381)
		(layer "F.Cu")
		(net "GND")
	)
	(segment
		(start 421.840914 -250.016772)
		(end 422.945814 -250.016772)
		(width 0.381)
		(layer "F.Cu")
		(net "GND")
	)
	(segment
		(start 136.075166 -236.319822)
		(end 136.075166 -235.783882)
		(width 0.254)
		(layer "F.Cu")
		(net "GND")
	)
	(segment
		(start 182.42788 -99.259898)
		(end 182.42788 -98.643948)
		(width 0.3556)
		(layer "F.Cu")
		(net "GND")
	)
	(segment
		(start 172.795946 -278.066754)
		(end 173.900846 -278.066754)
		(width 0.381)
		(layer "F.Cu")
		(net "GND")
	)
	(segment
		(start 201.279506 -105.715054)
		(end 201.06386 -105.9307)
		(width 0.3556)
		(layer "F.Cu")
		(net "GND")
	)
	(segment
		(start 443.367414 -265.316716)
		(end 444.472314 -265.316716)
		(width 0.381)
		(layer "F.Cu")
		(net "GND")
	)
	(segment
		(start 169.42308 -57.343548)
		(end 169.21099 -57.555638)
		(width 0.3556)
		(layer "F.Cu")
		(net "GND")
	)
	(segment
		(start 49.959514 -226.216718)
		(end 51.064414 -226.216718)
		(width 0.381)
		(layer "F.Cu")
		(net "GND")
	)
	(segment
		(start 376.48515 -106.739182)
		(end 376.48515 -107.183428)
		(width 0.3556)
		(layer "F.Cu")
		(net "GND")
	)
	(segment
		(start 93.88856 -333.786988)
		(end 93.88856 -333.324708)
		(width 0.2032)
		(layer "F.Cu")
		(net "GND")
	)
	(segment
		(start 375.718578 -96.212152)
		(end 375.718578 -95.081852)
		(width 0.3556)
		(layer "F.Cu")
		(net "GND")
	)
	(segment
		(start 311.882282 -280.61666)
		(end 312.987182 -280.61666)
		(width 0.381)
		(layer "F.Cu")
		(net "GND")
	)
	(segment
		(start 348.30258 -232.528618)
		(end 348.302834 -232.528364)
		(width 0.254)
		(layer "F.Cu")
		(net "GND")
	)
	(segment
		(start 463.659982 -216.866724)
		(end 464.764882 -216.866724)
		(width 0.381)
		(layer "F.Cu")
		(net "GND")
	)
	(segment
		(start 294.82288 -46.554898)
		(end 294.82288 -45.938948)
		(width 0.3556)
		(layer "F.Cu")
		(net "GND")
	)
	(segment
		(start 52.082446 -295.06672)
		(end 53.403246 -295.06672)
		(width 0.381)
		(layer "F.Cu")
		(net "GND")
	)
	(segment
		(start 100.832666 -228.99497)
		(end 100.832412 -228.994716)
		(width 0.2032)
		(layer "F.Cu")
		(net "GND")
	)
	(segment
		(start 8.140446 -315.46673)
		(end 9.245346 -315.46673)
		(width 0.381)
		(layer "F.Cu")
		(net "GND")
	)
	(segment
		(start 336.085434 -215.158574)
		(end 336.085434 -214.622888)
		(width 0.2032)
		(layer "F.Cu")
		(net "GND")
	)
	(segment
		(start 162.913314 -194.766692)
		(end 164.018214 -194.766692)
		(width 0.381)
		(layer "F.Cu")
		(net "GND")
	)
	(segment
		(start 294.904414 -227.066602)
		(end 293.799514 -227.066602)
		(width 0.381)
		(layer "F.Cu")
		(net "GND")
	)
	(segment
		(start 118.218712 -216.250774)
		(end 118.218966 -216.25052)
		(width 0.254)
		(layer "F.Cu")
		(net "GND")
	)
	(segment
		(start 132.315966 -234.691936)
		(end 132.315966 -234.15625)
		(width 0.2032)
		(layer "F.Cu")
		(net "GND")
	)
	(segment
		(start 132.425694 -285.939484)
		(end 132.425694 -286.475424)
		(width 0.2032)
		(layer "F.Cu")
		(net "GND")
	)
	(segment
		(start 178.000914 -308.666642)
		(end 179.105814 -308.666642)
		(width 0.381)
		(layer "F.Cu")
		(net "GND")
	)
	(segment
		(start 281.794966 -91.529154)
		(end 281.794966 -92.51569)
		(width 0.3556)
		(layer "F.Cu")
		(net "GND")
	)
	(segment
		(start 42.415714 -250.866656)
		(end 41.310814 -250.866656)
		(width 0.381)
		(layer "F.Cu")
		(net "GND")
	)
	(segment
		(start 139.004294 -258.2672)
		(end 139.445492 -258.06654)
		(width 0.254)
		(layer "F.Cu")
		(net "GND")
	)
	(segment
		(start 210.514946 -223.666558)
		(end 211.619846 -223.666558)
		(width 0.381)
		(layer "F.Cu")
		(net "GND")
	)
	(segment
		(start 261.285482 -196.466714)
		(end 260.180582 -196.466714)
		(width 0.381)
		(layer "F.Cu")
		(net "GND")
	)
	(segment
		(start 123.387612 -240.388902)
		(end 123.387612 -239.853216)
		(width 0.2032)
		(layer "F.Cu")
		(net "GND")
	)
	(segment
		(start 428.279814 -221.96679)
		(end 429.384714 -221.96679)
		(width 0.381)
		(layer "F.Cu")
		(net "GND")
	)
	(segment
		(start 198.81469 -68.026788)
		(end 199.42429 -68.026788)
		(width 0.3556)
		(layer "F.Cu")
		(net "GND")
	)
	(segment
		(start 281.707082 -230.466646)
		(end 282.811982 -230.466646)
		(width 0.381)
		(layer "F.Cu")
		(net "GND")
	)
	(segment
		(start 342.664034 -216.786206)
		(end 342.664034 -216.25052)
		(width 0.254)
		(layer "F.Cu")
		(net "GND")
	)
	(segment
		(start 101.412548 -256.639568)
		(end 101.412548 -257.175254)
		(width 0.2032)
		(layer "F.Cu")
		(net "GND")
	)
	(segment
		(start 132.895848 -255.825498)
		(end 132.895848 -256.361184)
		(width 0.254)
		(layer "F.Cu")
		(net "GND")
	)
	(segment
		(start 131.016248 -281.869896)
		(end 131.015994 -282.405836)
		(width 0.254)
		(layer "F.Cu")
		(net "GND")
	)
	(segment
		(start 127.726694 -271.289272)
		(end 127.726948 -271.825212)
		(width 0.2032)
		(layer "F.Cu")
		(net "GND")
	)
	(segment
		(start 376.136916 -284.033468)
		(end 376.136662 -284.033722)
		(width 0.254)
		(layer "F.Cu")
		(net "GND")
	)
	(segment
		(start 380.365762 -272.917158)
		(end 380.366016 -273.453098)
		(width 0.2032)
		(layer "F.Cu")
		(net "GND")
	)
	(segment
		(start 207.071214 -314.616592)
		(end 208.176114 -314.616592)
		(width 0.381)
		(layer "F.Cu")
		(net "GND")
	)
	(segment
		(start 277.607014 -251.716794)
		(end 278.711914 -251.716794)
		(width 0.381)
		(layer "F.Cu")
		(net "GND")
	)
	(segment
		(start 42.415714 -299.316648)
		(end 41.310814 -299.316648)
		(width 0.381)
		(layer "F.Cu")
		(net "GND")
	)
	(segment
		(start 443.367414 -287.416748)
		(end 444.472314 -287.416748)
		(width 0.381)
		(layer "F.Cu")
		(net "GND")
	)
	(segment
		(start 328.244962 -52.952396)
		(end 328.194162 -52.901596)
		(width 0.2032)
		(layer "F.Cu")
		(net "GND")
	)
	(segment
		(start 463.659982 -280.61666)
		(end 462.555082 -280.61666)
		(width 0.381)
		(layer "F.Cu")
		(net "GND")
	)
	(segment
		(start 377.076716 -255.825498)
		(end 377.076716 -256.361438)
		(width 0.2032)
		(layer "F.Cu")
		(net "GND")
	)
	(segment
		(start 101.882448 -280.242264)
		(end 101.882448 -280.77795)
		(width 0.2032)
		(layer "F.Cu")
		(net "GND")
	)
	(segment
		(start 361.45978 -232.528618)
		(end 361.460034 -232.528364)
		(width 0.2032)
		(layer "F.Cu")
		(net "GND")
	)
	(segment
		(start 98.123248 -283.497782)
		(end 98.123248 -284.033468)
		(width 0.254)
		(layer "F.Cu")
		(net "GND")
	)
	(segment
		(start 342.735154 -42.341292)
		(end 342.912192 -42.649648)
		(width 0.2032)
		(layer "F.Cu")
		(net "GND")
	)
	(segment
		(start 112.110266 -235.506006)
		(end 112.110266 -234.970066)
		(width 0.254)
		(layer "F.Cu")
		(net "GND")
	)
	(segment
		(start 406.753314 -251.716794)
		(end 407.858214 -251.716794)
		(width 0.381)
		(layer "F.Cu")
		(net "GND")
	)
	(segment
		(start 29.666946 -233.016806)
		(end 30.771846 -233.016806)
		(width 0.381)
		(layer "F.Cu")
		(net "GND")
	)
	(segment
		(start 108.27893 -57.241948)
		(end 108.27893 -57.876948)
		(width 0.3556)
		(layer "F.Cu")
		(net "GND")
	)
	(segment
		(start 275.268182 -244.066568)
		(end 274.163282 -244.066568)
		(width 0.381)
		(layer "F.Cu")
		(net "GND")
	)
	(segment
		(start 214.615014 -224.516696)
		(end 215.719914 -224.516696)
		(width 0.381)
		(layer "F.Cu")
		(net "GND")
	)
	(segment
		(start 277.607014 -273.816572)
		(end 278.711914 -273.816572)
		(width 0.381)
		(layer "F.Cu")
		(net "GND")
	)
	(segment
		(start 74.21753 -162.003486)
		(end 74.843132 -162.003486)
		(width 0.3556)
		(layer "F.Cu")
		(net "GND")
	)
	(segment
		(start 289.250882 -198.166736)
		(end 290.355782 -198.166736)
		(width 0.381)
		(layer "F.Cu")
		(net "GND")
	)
	(segment
		(start 94.364048 -255.825498)
		(end 94.364048 -256.361438)
		(width 0.2032)
		(layer "F.Cu")
		(net "GND")
	)
	(segment
		(start 282.811982 -210.066636)
		(end 283.916882 -210.066636)
		(width 0.381)
		(layer "F.Cu")
		(net "GND")
	)
	(segment
		(start 214.615014 -202.416664)
		(end 215.719914 -202.416664)
		(width 0.381)
		(layer "F.Cu")
		(net "GND")
	)
	(segment
		(start 289.250882 -310.366664)
		(end 290.355782 -310.366664)
		(width 0.381)
		(layer "F.Cu")
		(net "GND")
	)
	(segment
		(start 418.397182 -230.466646)
		(end 417.292282 -230.466646)
		(width 0.381)
		(layer "F.Cu")
		(net "GND")
	)
	(segment
		(start 136.184894 -276.172676)
		(end 136.184894 -276.708616)
		(width 0.254)
		(layer "F.Cu")
		(net "GND")
	)
	(segment
		(start 422.945814 -273.587972)
		(end 422.717214 -273.816572)
		(width 0.381)
		(layer "F.Cu")
		(net "GND")
	)
	(segment
		(start 262.519414 -306.116736)
		(end 263.624314 -306.116736)
		(width 0.381)
		(layer "F.Cu")
		(net "GND")
	)
	(segment
		(start 96.133666 -235.506006)
		(end 96.133412 -235.505752)
		(width 0.2032)
		(layer "F.Cu")
		(net "GND")
	)
	(segment
		(start 368.148362 -287.567116)
		(end 368.148362 -288.103056)
		(width 0.254)
		(layer "F.Cu")
		(net "GND")
	)
	(segment
		(start 335.14538 -242.830858)
		(end 335.14538 -242.294918)
		(width 0.254)
		(layer "F.Cu")
		(net "GND")
	)
	(segment
		(start 278.711914 -251.716794)
		(end 279.816814 -251.716794)
		(width 0.381)
		(layer "F.Cu")
		(net "GND")
	)
	(segment
		(start 29.666946 -292.516814)
		(end 30.771846 -292.516814)
		(width 0.381)
		(layer "F.Cu")
		(net "GND")
	)
	(segment
		(start 365.60125 -414.7566)
		(end 366.2172 -414.7566)
		(width 0.3556)
		(layer "F.Cu")
		(net "GND")
	)
	(segment
		(start 383.545334 -220.855794)
		(end 383.545334 -220.319854)
		(width 0.2032)
		(layer "F.Cu")
		(net "GND")
	)
	(segment
		(start 299.890434 -423.05605)
		(end 299.890434 -423.56532)
		(width 0.3556)
		(layer "F.Cu")
		(net "GND")
	)
	(segment
		(start 179.105814 -241.516662)
		(end 178.000914 -241.516662)
		(width 0.381)
		(layer "F.Cu")
		(net "GND")
	)
	(segment
		(start 45.859446 -261.916672)
		(end 46.964346 -261.916672)
		(width 0.381)
		(layer "F.Cu")
		(net "GND")
	)
	(segment
		(start 122.917712 -239.57534)
		(end 122.917712 -239.0394)
		(width 0.2032)
		(layer "F.Cu")
		(net "GND")
	)
	(segment
		(start 196.532246 -197.316598)
		(end 197.637146 -197.316598)
		(width 0.381)
		(layer "F.Cu")
		(net "GND")
	)
	(segment
		(start 428.279814 -313.766708)
		(end 429.384714 -313.766708)
		(width 0.381)
		(layer "F.Cu")
		(net "GND")
	)
	(segment
		(start 177.355754 -115.375436)
		(end 176.955704 -115.775486)
		(width 0.3556)
		(layer "F.Cu")
		(net "GND")
	)
	(segment
		(start 15.684246 -238.966756)
		(end 16.789146 -238.966756)
		(width 0.381)
		(layer "F.Cu")
		(net "GND")
	)
	(segment
		(start 196.532246 -251.716794)
		(end 197.637146 -251.716794)
		(width 0.381)
		(layer "F.Cu")
		(net "GND")
	)
	(segment
		(start 278.711914 -276.366732)
		(end 279.816814 -276.366732)
		(width 0.381)
		(layer "F.Cu")
		(net "GND")
	)
	(segment
		(start 461.979264 -120.020334)
		(end 461.979264 -119.093488)
		(width 0.3556)
		(layer "F.Cu")
		(net "GND")
	)
	(segment
		(start 413.192214 -203.266802)
		(end 414.297114 -203.266802)
		(width 0.381)
		(layer "F.Cu")
		(net "GND")
	)
	(segment
		(start 53.403246 -304.416714)
		(end 54.508146 -304.416714)
		(width 0.381)
		(layer "F.Cu")
		(net "GND")
	)
	(segment
		(start 199.527414 -244.066568)
		(end 200.632314 -244.066568)
		(width 0.381)
		(layer "F.Cu")
		(net "GND")
	)
	(segment
		(start 34.871914 -249.166634)
		(end 35.976814 -249.166634)
		(width 0.381)
		(layer "F.Cu")
		(net "GND")
	)
	(segment
		(start 419.705282 -275.516594)
		(end 418.397182 -275.516594)
		(width 0.381)
		(layer "F.Cu")
		(net "GND")
	)
	(segment
		(start 42.415714 -226.216718)
		(end 41.310814 -226.216718)
		(width 0.381)
		(layer "F.Cu")
		(net "GND")
	)
	(segment
		(start 39.420546 -201.56678)
		(end 38.315646 -201.56678)
		(width 0.381)
		(layer "F.Cu")
		(net "GND")
	)
	(segment
		(start 367.227358 -92.562934)
		(end 367.227358 -91.953334)
		(width 0.3556)
		(layer "F.Cu")
		(net "GND")
	)
	(segment
		(start 191.983614 -271.266666)
		(end 193.088514 -271.266666)
		(width 0.381)
		(layer "F.Cu")
		(net "GND")
	)
	(segment
		(start 38.424358 -355.990144)
		(end 38.424358 -355.77145)
		(width 0.2032)
		(layer "F.Cu")
		(net "GND")
	)
	(segment
		(start 414.297114 -270.416782)
		(end 415.402014 -270.416782)
		(width 0.381)
		(layer "F.Cu")
		(net "GND")
	)
	(segment
		(start 363.80928 -230.622348)
		(end 363.80928 -230.086662)
		(width 0.2032)
		(layer "F.Cu")
		(net "GND")
	)
	(segment
		(start 377.546362 -282.683966)
		(end 377.546362 -283.219906)
		(width 0.254)
		(layer "F.Cu")
		(net "GND")
	)
	(segment
		(start 260.180582 -291.666676)
		(end 259.075682 -291.666676)
		(width 0.381)
		(layer "F.Cu")
		(net "GND")
	)
	(segment
		(start 286.255714 -300.166786)
		(end 287.360614 -300.166786)
		(width 0.381)
		(layer "F.Cu")
		(net "GND")
	)
	(segment
		(start 210.514946 -263.616694)
		(end 211.619846 -263.616694)
		(width 0.381)
		(layer "F.Cu")
		(net "GND")
	)
	(segment
		(start 48.13173 -353.628452)
		(end 48.13173 -353.162616)
		(width 0.2032)
		(layer "F.Cu")
		(net "GND")
	)
	(segment
		(start 11.135614 -269.566644)
		(end 12.240514 -269.566644)
		(width 0.381)
		(layer "F.Cu")
		(net "GND")
	)
	(segment
		(start 185.544714 -216.866724)
		(end 186.649614 -216.866724)
		(width 0.381)
		(layer "F.Cu")
		(net "GND")
	)
	(segment
		(start 330.706222 -35.677348)
		(end 330.706222 -35.74542)
		(width 0.2032)
		(layer "F.Cu")
		(net "GND")
	)
	(segment
		(start 33.767014 -194.766692)
		(end 34.871914 -194.766692)
		(width 0.381)
		(layer "F.Cu")
		(net "GND")
	)
	(segment
		(start 211.619846 -201.56678)
		(end 210.514946 -201.56678)
		(width 0.381)
		(layer "F.Cu")
		(net "GND")
	)
	(segment
		(start 134.305548 -270.167862)
		(end 134.305548 -270.19758)
		(width 0.2032)
		(layer "F.Cu")
		(net "GND")
	)
	(segment
		(start 332.906116 -265.592306)
		(end 332.435962 -265.314176)
		(width 0.254)
		(layer "F.Cu")
		(net "GND")
	)
	(segment
		(start 45.859446 -208.366614)
		(end 46.964346 -208.366614)
		(width 0.381)
		(layer "F.Cu")
		(net "GND")
	)
	(segment
		(start 65.531238 -32.373062)
		(end 65.531238 -31.303722)
		(width 0.254)
		(layer "F.Cu")
		(net "GND")
	)
	(segment
		(start 28.638246 -397.406876)
		(end 28.028646 -397.406876)
		(width 0.3556)
		(layer "F.Cu")
		(net "GND")
	)
	(segment
		(start 328.244962 -40.946578)
		(end 328.244962 -40.686228)
		(width 0.2032)
		(layer "F.Cu")
		(net "GND")
	)
	(segment
		(start 410.853382 -222.816674)
		(end 411.958282 -222.816674)
		(width 0.381)
		(layer "F.Cu")
		(net "GND")
	)
	(segment
		(start 414.297114 -307.816758)
		(end 415.402014 -307.816758)
		(width 0.381)
		(layer "F.Cu")
		(net "GND")
	)
	(segment
		(start 460.664814 -229.616762)
		(end 459.559914 -229.616762)
		(width 0.381)
		(layer "F.Cu")
		(net "GND")
	)
	(segment
		(start 98.482912 -242.295172)
		(end 98.483166 -242.294918)
		(width 0.2032)
		(layer "F.Cu")
		(net "GND")
	)
	(segment
		(start 176.896014 -306.96662)
		(end 178.000914 -306.96662)
		(width 0.381)
		(layer "F.Cu")
		(net "GND")
	)
	(segment
		(start 421.840914 -231.316784)
		(end 422.945814 -231.316784)
		(width 0.381)
		(layer "F.Cu")
		(net "GND")
	)
	(segment
		(start 374.14708 -237.133638)
		(end 374.14708 -236.597952)
		(width 0.254)
		(layer "F.Cu")
		(net "GND")
	)
	(segment
		(start 254.975614 -234.716574)
		(end 256.080514 -234.716574)
		(width 0.381)
		(layer "F.Cu")
		(net "GND")
	)
	(segment
		(start 23.228046 -300.166786)
		(end 24.332946 -300.166786)
		(width 0.381)
		(layer "F.Cu")
		(net "GND")
	)
	(segment
		(start 365.21898 -226.017582)
		(end 365.219234 -226.017328)
		(width 0.254)
		(layer "F.Cu")
		(net "GND")
	)
	(segment
		(start 96.243648 -269.383256)
		(end 96.243394 -269.38351)
		(width 0.2032)
		(layer "F.Cu")
		(net "GND")
	)
	(segment
		(start 424.69816 -144.075658)
		(end 424.69816 -144.689068)
		(width 0.3556)
		(layer "F.Cu")
		(net "GND")
	)
	(segment
		(start 368.148362 -279.428194)
		(end 368.148362 -279.96388)
		(width 0.254)
		(layer "F.Cu")
		(net "GND")
	)
	(segment
		(start 159.791146 -285.716726)
		(end 158.813246 -285.716726)
		(width 0.381)
		(layer "F.Cu")
		(net "GND")
	)
	(segment
		(start 342.304116 -264.500106)
		(end 342.303862 -264.50036)
		(width 0.254)
		(layer "F.Cu")
		(net "GND")
	)
	(segment
		(start 333.23784 -13.317982)
		(end 333.23784 -12.616688)
		(width 0.3556)
		(layer "F.Cu")
		(net "GND")
	)
	(segment
		(start 456.116182 -219.41663)
		(end 455.011282 -219.41663)
		(width 0.381)
		(layer "F.Cu")
		(net "GND")
	)
	(segment
		(start 378.956316 -281.869896)
		(end 378.956062 -282.405836)
		(width 0.254)
		(layer "F.Cu")
		(net "GND")
	)
	(segment
		(start 28.638246 -392.326876)
		(end 28.028646 -392.326876)
		(width 0.3556)
		(layer "F.Cu")
		(net "GND")
	)
	(segment
		(start 260.180582 -295.916604)
		(end 259.075682 -295.916604)
		(width 0.381)
		(layer "F.Cu")
		(net "GND")
	)
	(segment
		(start 410.853382 -308.666642)
		(end 409.748482 -308.666642)
		(width 0.381)
		(layer "F.Cu")
		(net "GND")
	)
	(segment
		(start 300.238414 -263.616694)
		(end 301.343314 -263.616694)
		(width 0.381)
		(layer "F.Cu")
		(net "GND")
	)
	(segment
		(start 101.516942 -338.493862)
		(end 101.389434 -338.366354)
		(width 0.381)
		(layer "F.Cu")
		(net "GND")
	)
	(segment
		(start 311.882282 -306.96662)
		(end 312.987182 -306.96662)
		(width 0.381)
		(layer "F.Cu")
		(net "GND")
	)
	(segment
		(start 20.024852 -52.999894)
		(end 21.96846 -52.999894)
		(width 0.3556)
		(layer "F.Cu")
		(net "GND")
	)
	(segment
		(start 48.854614 -258.516628)
		(end 49.959514 -258.516628)
		(width 0.381)
		(layer "F.Cu")
		(net "GND")
	)
	(segment
		(start 301.343314 -278.066754)
		(end 302.448214 -278.066754)
		(width 0.381)
		(layer "F.Cu")
		(net "GND")
	)
	(segment
		(start 362.979716 -278.614378)
		(end 362.979716 -279.150064)
		(width 0.254)
		(layer "F.Cu")
		(net "GND")
	)
	(segment
		(start 11.135614 -284.866588)
		(end 12.240514 -284.866588)
		(width 0.381)
		(layer "F.Cu")
		(net "GND")
	)
	(segment
		(start 210.514946 -225.36658)
		(end 211.619846 -225.36658)
		(width 0.381)
		(layer "F.Cu")
		(net "GND")
	)
	(segment
		(start 335.255616 -288.102802)
		(end 335.255362 -288.103056)
		(width 0.254)
		(layer "F.Cu")
		(net "GND")
	)
	(segment
		(start 121.618248 -280.242264)
		(end 121.617994 -280.778204)
		(width 0.254)
		(layer "F.Cu")
		(net "GND")
	)
	(segment
		(start 324.873112 -20.148296)
		(end 324.6882 -20.333208)
		(width 0.3556)
		(layer "F.Cu")
		(net "GND")
	)
	(segment
		(start 445.577214 -267.016738)
		(end 444.472314 -267.016738)
		(width 0.381)
		(layer "F.Cu")
		(net "GND")
	)
	(segment
		(start 114.929666 -215.972644)
		(end 114.929412 -215.97239)
		(width 0.2032)
		(layer "F.Cu")
		(net "GND")
	)
	(segment
		(start 419.502082 -221.116652)
		(end 418.397182 -221.116652)
		(width 0.381)
		(layer "F.Cu")
		(net "GND")
	)
	(segment
		(start 177.108104 -42.29989)
		(end 178.289204 -42.29989)
		(width 0.254)
		(layer "F.Cu")
		(net "GND")
	)
	(segment
		(start 260.180582 -312.91657)
		(end 259.075682 -312.91657)
		(width 0.381)
		(layer "F.Cu")
		(net "GND")
	)
	(segment
		(start 345.593162 -253.919482)
		(end 345.593416 -253.919736)
		(width 0.2032)
		(layer "F.Cu")
		(net "GND")
	)
	(segment
		(start 370.85778 -241.203226)
		(end 370.85778 -240.667286)
		(width 0.254)
		(layer "F.Cu")
		(net "GND")
	)
	(segment
		(start 460.664814 -206.666592)
		(end 459.559914 -206.666592)
		(width 0.381)
		(layer "F.Cu")
		(net "GND")
	)
	(segment
		(start 256.080514 -279.766776)
		(end 257.185414 -279.766776)
		(width 0.381)
		(layer "F.Cu")
		(net "GND")
	)
	(segment
		(start 345.403932 -58.850276)
		(end 344.903552 -58.43524)
		(width 0.2032)
		(layer "F.Cu")
		(net "GND")
	)
	(segment
		(start 51.467004 -9.424924)
		(end 51.467004 -8.320024)
		(width 0.3556)
		(layer "F.Cu")
		(net "GND")
	)
	(segment
		(start 7.495286 -101.738938)
		(end 7.610348 -101.854)
		(width 0.3556)
		(layer "F.Cu")
		(net "GND")
	)
	(segment
		(start 354.88118 -229.808786)
		(end 354.881434 -229.808532)
		(width 0.2032)
		(layer "F.Cu")
		(net "GND")
	)
	(segment
		(start 433.484782 -312.91657)
		(end 434.589682 -312.91657)
		(width 0.381)
		(layer "F.Cu")
		(net "GND")
	)
	(segment
		(start 110.340648 -272.639028)
		(end 110.340394 -272.639282)
		(width 0.254)
		(layer "F.Cu")
		(net "GND")
	)
	(segment
		(start 110.340648 -268.84757)
		(end 110.340648 -269.383256)
		(width 0.254)
		(layer "F.Cu")
		(net "GND")
	)
	(segment
		(start 175.005746 -261.916672)
		(end 173.900846 -261.916672)
		(width 0.381)
		(layer "F.Cu")
		(net "GND")
	)
	(segment
		(start 345.48318 -241.203226)
		(end 345.48318 -240.667286)
		(width 0.2032)
		(layer "F.Cu")
		(net "GND")
	)
	(segment
		(start 167.461946 -304.416714)
		(end 166.357046 -304.416714)
		(width 0.381)
		(layer "F.Cu")
		(net "GND")
	)
	(segment
		(start 289.250882 -280.61666)
		(end 290.355782 -280.61666)
		(width 0.381)
		(layer "F.Cu")
		(net "GND")
	)
	(segment
		(start 162.913314 -222.816674)
		(end 161.808414 -222.816674)
		(width 0.381)
		(layer "F.Cu")
		(net "GND")
	)
	(segment
		(start 84.856066 -227.367084)
		(end 84.855812 -226.831144)
		(width 0.2032)
		(layer "F.Cu")
		(net "GND")
	)
	(segment
		(start 135.120888 -344.741754)
		(end 134.80669 -345.055952)
		(width 0.1778)
		(layer "F.Cu")
		(net "GND")
	)
	(segment
		(start 353.111562 -287.567116)
		(end 353.111816 -288.103056)
		(width 0.254)
		(layer "F.Cu")
		(net "GND")
	)
	(segment
		(start 49.959514 -275.516594)
		(end 48.638714 -275.516594)
		(width 0.381)
		(layer "F.Cu")
		(net "GND")
	)
	(segment
		(start 372.73738 -226.553268)
		(end 372.73738 -226.017582)
		(width 0.254)
		(layer "F.Cu")
		(net "GND")
	)
	(segment
		(start 52.298346 -248.31675)
		(end 53.403246 -248.31675)
		(width 0.381)
		(layer "F.Cu")
		(net "GND")
	)
	(segment
		(start 262.519414 -281.466798)
		(end 263.624314 -281.466798)
		(width 0.381)
		(layer "F.Cu")
		(net "GND")
	)
	(segment
		(start 92.954094 -272.917158)
		(end 92.954094 -273.452844)
		(width 0.2032)
		(layer "F.Cu")
		(net "GND")
	)
	(segment
		(start 29.666946 -315.46673)
		(end 30.771846 -315.46673)
		(width 0.381)
		(layer "F.Cu")
		(net "GND")
	)
	(segment
		(start 286.260032 -387.147562)
		(end 286.260032 -390.459976)
		(width 0.4572)
		(layer "F.Cu")
		(net "GND")
	)
	(segment
		(start 418.397182 -235.566712)
		(end 417.077652 -235.566712)
		(width 0.381)
		(layer "F.Cu")
		(net "GND")
	)
	(segment
		(start 171.562014 -200.716642)
		(end 170.457114 -200.716642)
		(width 0.381)
		(layer "F.Cu")
		(net "GND")
	)
	(segment
		(start 443.367414 -292.516814)
		(end 444.472314 -292.516814)
		(width 0.381)
		(layer "F.Cu")
		(net "GND")
	)
	(segment
		(start 8.140446 -240.666778)
		(end 9.245346 -240.666778)
		(width 0.381)
		(layer "F.Cu")
		(net "GND")
	)
	(segment
		(start 33.767014 -221.116652)
		(end 34.871914 -221.116652)
		(width 0.381)
		(layer "F.Cu")
		(net "GND")
	)
	(segment
		(start 463.659982 -198.166736)
		(end 464.764882 -198.166736)
		(width 0.381)
		(layer "F.Cu")
		(net "GND")
	)
	(segment
		(start 413.192214 -304.416714)
		(end 414.297114 -304.416714)
		(width 0.381)
		(layer "F.Cu")
		(net "GND")
	)
	(segment
		(start 211.619846 -206.666592)
		(end 212.724746 -206.666592)
		(width 0.381)
		(layer "F.Cu")
		(net "GND")
	)
	(segment
		(start 11.135614 -202.416664)
		(end 12.240514 -202.416664)
		(width 0.381)
		(layer "F.Cu")
		(net "GND")
	)
	(segment
		(start 123.027694 -258.2672)
		(end 123.027694 -258.80314)
		(width 0.254)
		(layer "F.Cu")
		(net "GND")
	)
	(segment
		(start 39.420546 -267.016738)
		(end 38.315646 -267.016738)
		(width 0.381)
		(layer "F.Cu")
		(net "GND")
	)
	(segment
		(start 460.664814 -201.56678)
		(end 459.559914 -201.56678)
		(width 0.381)
		(layer "F.Cu")
		(net "GND")
	)
	(segment
		(start 89.664794 -265.592306)
		(end 89.664794 -266.128246)
		(width 0.254)
		(layer "F.Cu")
		(net "GND")
	)
	(segment
		(start 178.000914 -228.766624)
		(end 176.896014 -228.766624)
		(width 0.381)
		(layer "F.Cu")
		(net "GND")
	)
	(segment
		(start 443.367414 -306.116736)
		(end 444.472314 -306.116736)
		(width 0.381)
		(layer "F.Cu")
		(net "GND")
	)
	(segment
		(start 383.655062 -286.7533)
		(end 383.655062 -287.28924)
		(width 0.2032)
		(layer "F.Cu")
		(net "GND")
	)
	(segment
		(start 308.887114 -315.46673)
		(end 309.992014 -315.46673)
		(width 0.381)
		(layer "F.Cu")
		(net "GND")
	)
	(segment
		(start 365.328962 -271.289272)
		(end 365.329216 -271.825212)
		(width 0.2032)
		(layer "F.Cu")
		(net "GND")
	)
	(segment
		(start 19.784314 -235.566712)
		(end 20.889214 -235.566712)
		(width 0.381)
		(layer "F.Cu")
		(net "GND")
	)
	(segment
		(start 110.340648 -262.336534)
		(end 110.340648 -262.872728)
		(width 0.254)
		(layer "F.Cu")
		(net "GND")
	)
	(segment
		(start 181.444646 -285.716726)
		(end 180.339746 -285.716726)
		(width 0.381)
		(layer "F.Cu")
		(net "GND")
	)
	(segment
		(start 29.666946 -250.016772)
		(end 30.771846 -250.016772)
		(width 0.381)
		(layer "F.Cu")
		(net "GND")
	)
	(segment
		(start 159.918146 -203.266802)
		(end 158.813246 -203.266802)
		(width 0.381)
		(layer "F.Cu")
		(net "GND")
	)
	(segment
		(start 175.005746 -258.516628)
		(end 173.900846 -258.516628)
		(width 0.381)
		(layer "F.Cu")
		(net "GND")
	)
	(segment
		(start 383.545334 -233.34218)
		(end 383.545334 -233.87812)
		(width 0.2032)
		(layer "F.Cu")
		(net "GND")
	)
	(segment
		(start 99.640136 -355.866192)
		(end 99.999546 -356.225602)
		(width 0.381)
		(layer "F.Cu")
		(net "GND")
	)
	(segment
		(start 127.616712 -244.458744)
		(end 127.616966 -244.45849)
		(width 0.2032)
		(layer "F.Cu")
		(net "GND")
	)
	(segment
		(start 290.355782 -262.76681)
		(end 291.460682 -262.76681)
		(width 0.381)
		(layer "F.Cu")
		(net "GND")
	)
	(segment
		(start 117.86108 -400.815048)
		(end 117.86108 -401.424648)
		(width 0.381)
		(layer "F.Cu")
		(net "GND")
	)
	(segment
		(start 383.185162 -279.428194)
		(end 383.185162 -279.96388)
		(width 0.254)
		(layer "F.Cu")
		(net "GND")
	)
	(segment
		(start 344.073734 -227.367084)
		(end 344.073734 -226.831144)
		(width 0.2032)
		(layer "F.Cu")
		(net "GND")
	)
	(segment
		(start 285.150814 -236.416596)
		(end 286.255714 -236.416596)
		(width 0.381)
		(layer "F.Cu")
		(net "GND")
	)
	(segment
		(start 196.532246 -263.616694)
		(end 197.637146 -263.616694)
		(width 0.381)
		(layer "F.Cu")
		(net "GND")
	)
	(segment
		(start 53.403246 -300.166786)
		(end 54.508146 -300.166786)
		(width 0.381)
		(layer "F.Cu")
		(net "GND")
	)
	(segment
		(start 263.624314 -236.416596)
		(end 264.729214 -236.416596)
		(width 0.381)
		(layer "F.Cu")
		(net "GND")
	)
	(segment
		(start 457.221082 -233.86669)
		(end 456.116182 -233.86669)
		(width 0.381)
		(layer "F.Cu")
		(net "GND")
	)
	(segment
		(start 173.900846 -287.416748)
		(end 175.005746 -287.416748)
		(width 0.381)
		(layer "F.Cu")
		(net "GND")
	)
	(segment
		(start 368.508534 -232.250488)
		(end 368.50828 -232.250234)
		(width 0.2032)
		(layer "F.Cu")
		(net "GND")
	)
	(segment
		(start 124.437648 -274.26666)
		(end 124.437394 -274.266914)
		(width 0.254)
		(layer "F.Cu")
		(net "GND")
	)
	(segment
		(start 286.255714 -261.916672)
		(end 287.360614 -261.916672)
		(width 0.381)
		(layer "F.Cu")
		(net "GND")
	)
	(segment
		(start 423.095674 -363.912658)
		(end 423.448734 -363.912658)
		(width 0.2032)
		(layer "F.Cu")
		(net "GND")
	)
	(segment
		(start 387.38556 -258.06654)
		(end 387.414516 -257.98907)
		(width 0.254)
		(layer "F.Cu")
		(net "GND")
	)
	(segment
		(start 374.726962 -279.428194)
		(end 374.726962 -279.964134)
		(width 0.2032)
		(layer "F.Cu")
		(net "GND")
	)
	(segment
		(start 425.940982 -222.816674)
		(end 427.045882 -222.816674)
		(width 0.381)
		(layer "F.Cu")
		(net "GND")
	)
	(segment
		(start 438.270142 -120.614186)
		(end 437.643016 -120.614186)
		(width 0.381)
		(layer "F.Cu")
		(net "GND")
	)
	(segment
		(start 352.06178 -234.69219)
		(end 352.062034 -234.691936)
		(width 0.2032)
		(layer "F.Cu")
		(net "GND")
	)
	(segment
		(start 30.771846 -250.016772)
		(end 31.876746 -250.016772)
		(width 0.381)
		(layer "F.Cu")
		(net "GND")
	)
	(segment
		(start 29.666946 -313.766708)
		(end 30.771846 -313.766708)
		(width 0.381)
		(layer "F.Cu")
		(net "GND")
	)
	(segment
		(start 186.649614 -316.316614)
		(end 185.544714 -316.316614)
		(width 0.381)
		(layer "F.Cu")
		(net "GND")
	)
	(segment
		(start 193.088514 -258.516628)
		(end 191.983614 -258.516628)
		(width 0.381)
		(layer "F.Cu")
		(net "GND")
	)
	(segment
		(start 375.666762 -263.68629)
		(end 375.667016 -263.686544)
		(width 0.2032)
		(layer "F.Cu")
		(net "GND")
	)
	(segment
		(start 137.594594 -257.988816)
		(end 137.594848 -257.98907)
		(width 0.254)
		(layer "F.Cu")
		(net "GND")
	)
	(segment
		(start 70.861936 -12.37488)
		(end 70.861936 -11.26998)
		(width 0.3556)
		(layer "F.Cu")
		(net "GND")
	)
	(segment
		(start 421.840914 -289.11677)
		(end 420.736014 -289.11677)
		(width 0.381)
		(layer "F.Cu")
		(net "GND")
	)
	(segment
		(start 301.343314 -244.916706)
		(end 302.448214 -244.916706)
		(width 0.381)
		(layer "F.Cu")
		(net "GND")
	)
	(segment
		(start 182.549546 -295.06672)
		(end 181.444646 -295.06672)
		(width 0.381)
		(layer "F.Cu")
		(net "GND")
	)
	(segment
		(start 137.124694 -283.219144)
		(end 137.124948 -283.219398)
		(width 0.254)
		(layer "F.Cu")
		(net "GND")
	)
	(segment
		(start 453.121014 -233.016806)
		(end 452.016114 -233.016806)
		(width 0.381)
		(layer "F.Cu")
		(net "GND")
	)
	(segment
		(start 256.080514 -204.96657)
		(end 257.185414 -204.96657)
		(width 0.381)
		(layer "F.Cu")
		(net "GND")
	)
	(segment
		(start 63.942214 -200.716642)
		(end 65.047114 -200.716642)
		(width 0.381)
		(layer "F.Cu")
		(net "GND")
	)
	(segment
		(start 464.764882 -295.916604)
		(end 463.659982 -295.916604)
		(width 0.381)
		(layer "F.Cu")
		(net "GND")
	)
	(segment
		(start 370.967762 -272.917158)
		(end 370.967762 -273.453098)
		(width 0.2032)
		(layer "F.Cu")
		(net "GND")
	)
	(segment
		(start 108.461048 -273.730974)
		(end 108.461048 -274.266914)
		(width 0.2032)
		(layer "F.Cu")
		(net "GND")
	)
	(segment
		(start 338.396072 -42.341546)
		(end 338.93506 -42.341546)
		(width 0.2032)
		(layer "F.Cu")
		(net "GND")
	)
	(segment
		(start 272.273014 -301.866808)
		(end 271.168114 -301.866808)
		(width 0.381)
		(layer "F.Cu")
		(net "GND")
	)
	(segment
		(start 125.267466 -230.622602)
		(end 125.267466 -230.086662)
		(width 0.2032)
		(layer "F.Cu")
		(net "GND")
	)
	(segment
		(start 188.988446 -292.516814)
		(end 187.883546 -292.516814)
		(width 0.381)
		(layer "F.Cu")
		(net "GND")
	)
	(segment
		(start 30.771846 -246.616728)
		(end 31.876746 -246.616728)
		(width 0.381)
		(layer "F.Cu")
		(net "GND")
	)
	(segment
		(start 409.551632 -219.41663)
		(end 410.853382 -219.41663)
		(width 0.381)
		(layer "F.Cu")
		(net "GND")
	)
	(segment
		(start 345.15171 -41.349422)
		(end 345.48699 -41.847008)
		(width 0.2032)
		(layer "F.Cu")
		(net "GND")
	)
	(segment
		(start 136.545066 -235.506006)
		(end 136.545066 -234.97032)
		(width 0.2032)
		(layer "F.Cu")
		(net "GND")
	)
	(segment
		(start 164.018214 -303.566576)
		(end 162.913314 -303.566576)
		(width 0.381)
		(layer "F.Cu")
		(net "GND")
	)
	(segment
		(start 371.437916 -281.869896)
		(end 371.437916 -282.405582)
		(width 0.254)
		(layer "F.Cu")
		(net "GND")
	)
	(segment
		(start 37.330634 -109.571282)
		(end 37.940234 -109.571282)
		(width 0.3556)
		(layer "F.Cu")
		(net "GND")
	)
	(segment
		(start 262.519414 -315.46673)
		(end 263.624314 -315.46673)
		(width 0.381)
		(layer "F.Cu")
		(net "GND")
	)
	(segment
		(start 439.923682 -235.566712)
		(end 441.028582 -235.566712)
		(width 0.381)
		(layer "F.Cu")
		(net "GND")
	)
	(segment
		(start 422.945814 -285.716726)
		(end 421.840914 -285.716726)
		(width 0.381)
		(layer "F.Cu")
		(net "GND")
	)
	(segment
		(start 410.853382 -235.566712)
		(end 409.490672 -235.566712)
		(width 0.381)
		(layer "F.Cu")
		(net "GND")
	)
	(segment
		(start 166.357046 -227.066602)
		(end 165.252146 -227.066602)
		(width 0.381)
		(layer "F.Cu")
		(net "GND")
	)
	(segment
		(start 124.327412 -248.527824)
		(end 124.327412 -247.992138)
		(width 0.2032)
		(layer "F.Cu")
		(net "GND")
	)
	(segment
		(start 366.268762 -282.683966)
		(end 366.268762 -283.219652)
		(width 0.254)
		(layer "F.Cu")
		(net "GND")
	)
	(segment
		(start 181.444646 -276.366732)
		(end 182.549546 -276.366732)
		(width 0.381)
		(layer "F.Cu")
		(net "GND")
	)
	(segment
		(start 448.572382 -297.616626)
		(end 447.467482 -297.616626)
		(width 0.381)
		(layer "F.Cu")
		(net "GND")
	)
	(segment
		(start 160.43783 -121.376948)
		(end 159.82188 -121.376948)
		(width 0.3556)
		(layer "F.Cu")
		(net "GND")
	)
	(segment
		(start 350.292162 -289.195002)
		(end 350.292162 -289.807142)
		(width 0.2032)
		(layer "F.Cu")
		(net "GND")
	)
	(segment
		(start 266.619482 -272.966688)
		(end 267.724382 -272.966688)
		(width 0.381)
		(layer "F.Cu")
		(net "GND")
	)
	(segment
		(start 436.928514 -287.416748)
		(end 438.033414 -287.416748)
		(width 0.381)
		(layer "F.Cu")
		(net "GND")
	)
	(segment
		(start 175.005746 -195.616576)
		(end 173.900846 -195.616576)
		(width 0.381)
		(layer "F.Cu")
		(net "GND")
	)
	(segment
		(start 131.016248 -270.475456)
		(end 131.015994 -271.011396)
		(width 0.2032)
		(layer "F.Cu")
		(net "GND")
	)
	(segment
		(start 384.015234 -215.158574)
		(end 384.015234 -214.546434)
		(width 0.254)
		(layer "F.Cu")
		(net "GND")
	)
	(segment
		(start 11.895836 -92.287598)
		(end 11.895836 -91.658948)
		(width 0.3556)
		(layer "F.Cu")
		(net "GND")
	)
	(segment
		(start 96.133666 -242.017042)
		(end 96.133412 -242.016788)
		(width 0.2032)
		(layer "F.Cu")
		(net "GND")
	)
	(segment
		(start 130.546094 -282.683966)
		(end 130.546094 -283.219906)
		(width 0.2032)
		(layer "F.Cu")
		(net "GND")
	)
	(segment
		(start 63.942214 -280.61666)
		(end 65.047114 -280.61666)
		(width 0.381)
		(layer "F.Cu")
		(net "GND")
	)
	(segment
		(start 115.219734 -92.583762)
		(end 115.219734 -92.329762)
		(width 0.3556)
		(layer "F.Cu")
		(net "GND")
	)
	(segment
		(start 359.58018 -222.76181)
		(end 359.580434 -222.761556)
		(width 0.254)
		(layer "F.Cu")
		(net "GND")
	)
	(segment
		(start 263.624314 -263.616694)
		(end 264.729214 -263.616694)
		(width 0.381)
		(layer "F.Cu")
		(net "GND")
	)
	(segment
		(start 328.244962 -48.950372)
		(end 328.625708 -48.450246)
		(width 0.1778)
		(layer "F.Cu")
		(net "GND")
	)
	(segment
		(start 420.736014 -268.71676)
		(end 421.840914 -268.71676)
		(width 0.381)
		(layer "F.Cu")
		(net "GND")
	)
	(segment
		(start 38.315646 -236.416596)
		(end 37.210746 -236.416596)
		(width 0.381)
		(layer "F.Cu")
		(net "GND")
	)
	(segment
		(start 214.615014 -299.316648)
		(end 215.719914 -299.316648)
		(width 0.381)
		(layer "F.Cu")
		(net "GND")
	)
	(segment
		(start 113.094262 -139.069826)
		(end 112.484662 -139.069826)
		(width 0.381)
		(layer "F.Cu")
		(net "GND")
	)
	(segment
		(start 195.427346 -195.616576)
		(end 196.532246 -195.616576)
		(width 0.381)
		(layer "F.Cu")
		(net "GND")
	)
	(segment
		(start 212.724746 -229.616762)
		(end 211.619846 -229.616762)
		(width 0.381)
		(layer "F.Cu")
		(net "GND")
	)
	(segment
		(start 337.699858 -48.450246)
		(end 337.299808 -48.050196)
		(width 0.2032)
		(layer "F.Cu")
		(net "GND")
	)
	(segment
		(start 339.484716 -256.361184)
		(end 339.484462 -256.361438)
		(width 0.2032)
		(layer "F.Cu")
		(net "GND")
	)
	(segment
		(start 121.977912 -216.78646)
		(end 121.977912 -216.250774)
		(width 0.254)
		(layer "F.Cu")
		(net "GND")
	)
	(segment
		(start 97.543112 -216.250774)
		(end 97.543366 -216.25052)
		(width 0.254)
		(layer "F.Cu")
		(net "GND")
	)
	(segment
		(start 333.23657 -50.329846)
		(end 334.099408 -49.650396)
		(width 0.2032)
		(layer "F.Cu")
		(net "GND")
	)
	(segment
		(start 372.737634 -220.041724)
		(end 372.737634 -219.506038)
		(width 0.254)
		(layer "F.Cu")
		(net "GND")
	)
	(segment
		(start 159.918146 -317.166752)
		(end 158.813246 -317.166752)
		(width 0.381)
		(layer "F.Cu")
		(net "GND")
	)
	(segment
		(start 200.632314 -275.516594)
		(end 201.737214 -275.516594)
		(width 0.381)
		(layer "F.Cu")
		(net "GND")
	)
	(segment
		(start 12.240514 -245.76659)
		(end 13.345414 -245.76659)
		(width 0.381)
		(layer "F.Cu")
		(net "GND")
	)
	(segment
		(start 342.194134 -228.99497)
		(end 342.19388 -228.994716)
		(width 0.2032)
		(layer "F.Cu")
		(net "GND")
	)
	(segment
		(start 376.606562 -289.195002)
		(end 376.606562 -289.807142)
		(width 0.2032)
		(layer "F.Cu")
		(net "GND")
	)
	(segment
		(start 456.116182 -299.316648)
		(end 455.011282 -299.316648)
		(width 0.381)
		(layer "F.Cu")
		(net "GND")
	)
	(segment
		(start 286.255714 -278.066754)
		(end 287.360614 -278.066754)
		(width 0.381)
		(layer "F.Cu")
		(net "GND")
	)
	(segment
		(start 98.013012 -237.133638)
		(end 98.013012 -236.597952)
		(width 0.2032)
		(layer "F.Cu")
		(net "GND")
	)
	(segment
		(start 121.038366 -220.041724)
		(end 121.038366 -219.506038)
		(width 0.254)
		(layer "F.Cu")
		(net "GND")
	)
	(segment
		(start 99.532694 -269.66164)
		(end 99.532948 -269.661894)
		(width 0.2032)
		(layer "F.Cu")
		(net "GND")
	)
	(segment
		(start 286.255714 -227.066602)
		(end 287.360614 -227.066602)
		(width 0.381)
		(layer "F.Cu")
		(net "GND")
	)
	(segment
		(start 271.168114 -251.716794)
		(end 270.063214 -251.716794)
		(width 0.381)
		(layer "F.Cu")
		(net "GND")
	)
	(segment
		(start 63.726314 -312.91657)
		(end 65.047114 -312.91657)
		(width 0.381)
		(layer "F.Cu")
		(net "GND")
	)
	(segment
		(start 435.823614 -199.01662)
		(end 436.928514 -199.01662)
		(width 0.381)
		(layer "F.Cu")
		(net "GND")
	)
	(segment
		(start 371.437916 -262.336534)
		(end 371.437916 -262.87222)
		(width 0.254)
		(layer "F.Cu")
		(net "GND")
	)
	(segment
		(start 349.352616 -271.289526)
		(end 349.352616 -271.825212)
		(width 0.2032)
		(layer "F.Cu")
		(net "GND")
	)
	(segment
		(start 332.422246 -47.980346)
		(end 332.693518 -47.510446)
		(width 0.2032)
		(layer "F.Cu")
		(net "GND")
	)
	(segment
		(start 274.12315 -14.143228)
		(end 273.0754 -14.143228)
		(width 0.3556)
		(layer "F.Cu")
		(net "GND")
	)
	(segment
		(start 339.954362 -259.894832)
		(end 339.954362 -260.430772)
		(width 0.2032)
		(layer "F.Cu")
		(net "GND")
	)
	(segment
		(start 122.448066 -243.644928)
		(end 122.447812 -243.644674)
		(width 0.254)
		(layer "F.Cu")
		(net "GND")
	)
	(segment
		(start 345.554554 -41.947084)
		(end 345.15171 -42.349928)
		(width 0.2032)
		(layer "F.Cu")
		(net "GND")
	)
	(segment
		(start 135.135112 -233.064304)
		(end 135.135112 -232.528618)
		(width 0.2032)
		(layer "F.Cu")
		(net "GND")
	)
	(segment
		(start 435.823614 -240.666778)
		(end 436.928514 -240.666778)
		(width 0.381)
		(layer "F.Cu")
		(net "GND")
	)
	(segment
		(start 95.303848 -283.497782)
		(end 95.303848 -284.033468)
		(width 0.254)
		(layer "F.Cu")
		(net "GND")
	)
	(segment
		(start 261.285482 -284.866588)
		(end 260.180582 -284.866588)
		(width 0.381)
		(layer "F.Cu")
		(net "GND")
	)
	(segment
		(start 294.904414 -292.516814)
		(end 293.799514 -292.516814)
		(width 0.381)
		(layer "F.Cu")
		(net "GND")
	)
	(segment
		(start 19.784314 -295.916604)
		(end 20.889214 -295.916604)
		(width 0.381)
		(layer "F.Cu")
		(net "GND")
	)
	(segment
		(start 86.375494 -259.894832)
		(end 86.845394 -259.616956)
		(width 0.254)
		(layer "F.Cu")
		(net "GND")
	)
	(segment
		(start 414.297114 -285.716726)
		(end 415.630614 -285.716726)
		(width 0.381)
		(layer "F.Cu")
		(net "GND")
	)
	(segment
		(start 202.971146 -238.966756)
		(end 204.076046 -238.966756)
		(width 0.381)
		(layer "F.Cu")
		(net "GND")
	)
	(segment
		(start 166.357046 -304.416714)
		(end 165.252146 -304.416714)
		(width 0.381)
		(layer "F.Cu")
		(net "GND")
	)
	(segment
		(start 345.403932 -38.880288)
		(end 346.319348 -38.880288)
		(width 0.2032)
		(layer "F.Cu")
		(net "GND")
	)
	(segment
		(start 166.357046 -220.266768)
		(end 164.989002 -220.266768)
		(width 0.381)
		(layer "F.Cu")
		(net "GND")
	)
	(segment
		(start 178.13782 -356.43058)
		(end 178.614832 -355.953568)
		(width 0.2032)
		(layer "F.Cu")
		(net "GND")
	)
	(segment
		(start 308.887114 -208.366614)
		(end 310.207914 -208.366614)
		(width 0.381)
		(layer "F.Cu")
		(net "GND")
	)
	(segment
		(start 29.666946 -214.316564)
		(end 30.771846 -214.316564)
		(width 0.381)
		(layer "F.Cu")
		(net "GND")
	)
	(segment
		(start 344.653362 -289.195002)
		(end 344.653362 -289.807142)
		(width 0.2032)
		(layer "F.Cu")
		(net "GND")
	)
	(segment
		(start 463.659982 -244.066568)
		(end 464.764882 -244.066568)
		(width 0.381)
		(layer "F.Cu")
		(net "GND")
	)
	(segment
		(start 439.923682 -289.966654)
		(end 441.028582 -289.966654)
		(width 0.381)
		(layer "F.Cu")
		(net "GND")
	)
	(segment
		(start 411.958282 -271.266666)
		(end 410.853382 -271.266666)
		(width 0.381)
		(layer "F.Cu")
		(net "GND")
	)
	(segment
		(start 193.088514 -210.066636)
		(end 191.983614 -210.066636)
		(width 0.381)
		(layer "F.Cu")
		(net "GND")
	)
	(segment
		(start 42.415714 -286.56661)
		(end 41.310814 -286.56661)
		(width 0.381)
		(layer "F.Cu")
		(net "GND")
	)
	(segment
		(start 107.880912 -223.297496)
		(end 107.880912 -222.76181)
		(width 0.254)
		(layer "F.Cu")
		(net "GND")
	)
	(segment
		(start 30.771846 -203.266802)
		(end 31.876746 -203.266802)
		(width 0.381)
		(layer "F.Cu")
		(net "GND")
	)
	(segment
		(start 277.607014 -225.36658)
		(end 278.711914 -225.36658)
		(width 0.381)
		(layer "F.Cu")
		(net "GND")
	)
	(segment
		(start 459.559914 -307.816758)
		(end 460.664814 -307.816758)
		(width 0.381)
		(layer "F.Cu")
		(net "GND")
	)
	(segment
		(start 311.882282 -221.116652)
		(end 312.987182 -221.116652)
		(width 0.381)
		(layer "F.Cu")
		(net "GND")
	)
	(segment
		(start 161.808414 -299.316648)
		(end 162.913314 -299.316648)
		(width 0.381)
		(layer "F.Cu")
		(net "GND")
	)
	(segment
		(start 169.949622 -335.477612)
		(end 170.965622 -335.477612)
		(width 0.508)
		(layer "F.Cu")
		(net "GND")
	)
	(segment
		(start 56.398414 -301.01667)
		(end 57.503314 -301.01667)
		(width 0.381)
		(layer "F.Cu")
		(net "GND")
	)
	(segment
		(start 30.771846 -238.966756)
		(end 31.876746 -238.966756)
		(width 0.381)
		(layer "F.Cu")
		(net "GND")
	)
	(segment
		(start 406.524714 -364.151926)
		(end 410.361638 -364.151926)
		(width 0.381)
		(layer "F.Cu")
		(net "GND")
	)
	(segment
		(start 445.577214 -260.21665)
		(end 444.472314 -260.21665)
		(width 0.381)
		(layer "F.Cu")
		(net "GND")
	)
	(segment
		(start 424.836082 -226.216718)
		(end 425.940982 -226.216718)
		(width 0.381)
		(layer "F.Cu")
		(net "GND")
	)
	(segment
		(start 162.913314 -228.766624)
		(end 161.808414 -228.766624)
		(width 0.381)
		(layer "F.Cu")
		(net "GND")
	)
	(segment
		(start 113.519712 -245.551452)
		(end 113.52022 -245.550944)
		(width 0.254)
		(layer "F.Cu")
		(net "GND")
	)
	(segment
		(start 406.753314 -246.616728)
		(end 405.648414 -246.616728)
		(width 0.381)
		(layer "F.Cu")
		(net "GND")
	)
	(segment
		(start 361.45978 -239.57534)
		(end 361.45978 -239.0394)
		(width 0.254)
		(layer "F.Cu")
		(net "GND")
	)
	(segment
		(start 129.026412 -243.644674)
		(end 129.026412 -243.108988)
		(width 0.2032)
		(layer "F.Cu")
		(net "GND")
	)
	(segment
		(start 19.784314 -249.166634)
		(end 20.889214 -249.166634)
		(width 0.381)
		(layer "F.Cu")
		(net "GND")
	)
	(segment
		(start 32.350202 -161.570162)
		(end 32.337502 -161.582862)
		(width 0.254)
		(layer "F.Cu")
		(net "GND")
	)
	(segment
		(start 92.954094 -263.68629)
		(end 92.954348 -263.686544)
		(width 0.2032)
		(layer "F.Cu")
		(net "GND")
	)
	(segment
		(start 452.016114 -307.816758)
		(end 450.911214 -307.816758)
		(width 0.381)
		(layer "F.Cu")
		(net "GND")
	)
	(segment
		(start 94.833694 -285.939484)
		(end 94.833694 -286.475424)
		(width 0.2032)
		(layer "F.Cu")
		(net "GND")
	)
	(segment
		(start 165.252146 -214.316564)
		(end 166.357046 -214.316564)
		(width 0.381)
		(layer "F.Cu")
		(net "GND")
	)
	(segment
		(start 263.624314 -206.666592)
		(end 264.729214 -206.666592)
		(width 0.381)
		(layer "F.Cu")
		(net "GND")
	)
	(segment
		(start 462.555082 -249.166634)
		(end 463.659982 -249.166634)
		(width 0.381)
		(layer "F.Cu")
		(net "GND")
	)
	(segment
		(start 121.508266 -214.344758)
		(end 121.508266 -213.732618)
		(width 0.254)
		(layer "F.Cu")
		(net "GND")
	)
	(segment
		(start 8.140446 -290.816792)
		(end 9.245346 -290.816792)
		(width 0.381)
		(layer "F.Cu")
		(net "GND")
	)
	(segment
		(start 371.79758 -226.553268)
		(end 371.79758 -226.017582)
		(width 0.254)
		(layer "F.Cu")
		(net "GND")
	)
	(segment
		(start 102.75824 -335.541112)
		(end 102.386384 -335.541112)
		(width 0.1778)
		(layer "F.Cu")
		(net "GND")
	)
	(segment
		(start 56.398414 -205.816708)
		(end 57.503314 -205.816708)
		(width 0.381)
		(layer "F.Cu")
		(net "GND")
	)
	(segment
		(start 92.954348 -269.661894)
		(end 92.954348 -270.19758)
		(width 0.2032)
		(layer "F.Cu")
		(net "GND")
	)
	(segment
		(start 278.474678 -419.26129)
		(end 278.474678 -419.916102)
		(width 0.3556)
		(layer "F.Cu")
		(net "GND")
	)
	(segment
		(start 14.579346 -270.416782)
		(end 15.684246 -270.416782)
		(width 0.381)
		(layer "F.Cu")
		(net "GND")
	)
	(segment
		(start 444.472314 -223.666558)
		(end 443.367414 -223.666558)
		(width 0.381)
		(layer "F.Cu")
		(net "GND")
	)
	(segment
		(start 420.736014 -217.716608)
		(end 421.840914 -217.716608)
		(width 0.381)
		(layer "F.Cu")
		(net "GND")
	)
	(segment
		(start 346.42298 -222.76181)
		(end 346.423234 -222.761556)
		(width 0.254)
		(layer "F.Cu")
		(net "GND")
	)
	(segment
		(start 169.352214 -222.816674)
		(end 170.457114 -222.816674)
		(width 0.381)
		(layer "F.Cu")
		(net "GND")
	)
	(segment
		(start 463.659982 -286.56661)
		(end 462.555082 -286.56661)
		(width 0.381)
		(layer "F.Cu")
		(net "GND")
	)
	(segment
		(start 94.723712 -229.808786)
		(end 94.723712 -229.272846)
		(width 0.2032)
		(layer "F.Cu")
		(net "GND")
	)
	(segment
		(start 341.902034 -39.295324)
		(end 341.402162 -39.443152)
		(width 0.2032)
		(layer "F.Cu")
		(net "GND")
	)
	(segment
		(start 311.666382 -238.116618)
		(end 312.987182 -238.116618)
		(width 0.381)
		(layer "F.Cu")
		(net "GND")
	)
	(segment
		(start 190.093346 -233.016806)
		(end 188.988446 -233.016806)
		(width 0.381)
		(layer "F.Cu")
		(net "GND")
	)
	(segment
		(start 16.789146 -251.716794)
		(end 15.684246 -251.716794)
		(width 0.381)
		(layer "F.Cu")
		(net "GND")
	)
	(segment
		(start 368.618516 -287.288986)
		(end 368.618262 -287.28924)
		(width 0.254)
		(layer "F.Cu")
		(net "GND")
	)
	(segment
		(start 443.367414 -301.866808)
		(end 444.472314 -301.866808)
		(width 0.381)
		(layer "F.Cu")
		(net "GND")
	)
	(segment
		(start 130.906266 -224.111566)
		(end 130.906266 -223.575626)
		(width 0.2032)
		(layer "F.Cu")
		(net "GND")
	)
	(segment
		(start 103.181912 -226.017582)
		(end 103.182166 -226.017328)
		(width 0.254)
		(layer "F.Cu")
		(net "GND")
	)
	(segment
		(start 300.022514 -292.516814)
		(end 301.343314 -292.516814)
		(width 0.381)
		(layer "F.Cu")
		(net "GND")
	)
	(segment
		(start 38.315646 -267.016738)
		(end 37.210746 -267.016738)
		(width 0.381)
		(layer "F.Cu")
		(net "GND")
	)
	(segment
		(start 122.447812 -228.994716)
		(end 122.447812 -228.45903)
		(width 0.254)
		(layer "F.Cu")
		(net "GND")
	)
	(segment
		(start 256.080514 -260.21665)
		(end 257.185414 -260.21665)
		(width 0.381)
		(layer "F.Cu")
		(net "GND")
	)
	(segment
		(start 180.339746 -203.266802)
		(end 181.444646 -203.266802)
		(width 0.381)
		(layer "F.Cu")
		(net "GND")
	)
	(segment
		(start 267.724382 -245.76659)
		(end 268.829282 -245.76659)
		(width 0.381)
		(layer "F.Cu")
		(net "GND")
	)
	(segment
		(start 91.434412 -242.016788)
		(end 91.434412 -241.481102)
		(width 0.2032)
		(layer "F.Cu")
		(net "GND")
	)
	(segment
		(start 183.22163 -417.7157)
		(end 183.22163 -418.4142)
		(width 0.3556)
		(layer "F.Cu")
		(net "GND")
	)
	(segment
		(start 118.218712 -220.041978)
		(end 118.218966 -220.041724)
		(width 0.254)
		(layer "F.Cu")
		(net "GND")
	)
	(segment
		(start 27.131772 -412.08452)
		(end 26.496772 -412.08452)
		(width 0.3556)
		(layer "F.Cu")
		(net "GND")
	)
	(segment
		(start 123.387866 -220.855794)
		(end 123.387866 -220.319854)
		(width 0.2032)
		(layer "F.Cu")
		(net "GND")
	)
	(segment
		(start 311.882282 -289.966654)
		(end 312.987182 -289.966654)
		(width 0.381)
		(layer "F.Cu")
		(net "GND")
	)
	(segment
		(start 351.12198 -216.250774)
		(end 351.122234 -216.25052)
		(width 0.254)
		(layer "F.Cu")
		(net "GND")
	)
	(segment
		(start 337.495134 -243.644928)
		(end 337.49488 -243.644674)
		(width 0.2032)
		(layer "F.Cu")
		(net "GND")
	)
	(segment
		(start 39.420546 -298.466764)
		(end 38.315646 -298.466764)
		(width 0.381)
		(layer "F.Cu")
		(net "GND")
	)
	(segment
		(start 115.979448 -267.219938)
		(end 115.979194 -267.755878)
		(width 0.2032)
		(layer "F.Cu")
		(net "GND")
	)
	(segment
		(start 181.444646 -315.46673)
		(end 180.339746 -315.46673)
		(width 0.381)
		(layer "F.Cu")
		(net "GND")
	)
	(segment
		(start 30.771846 -307.816758)
		(end 31.876746 -307.816758)
		(width 0.381)
		(layer "F.Cu")
		(net "GND")
	)
	(segment
		(start 104.591866 -220.855794)
		(end 104.591866 -220.319854)
		(width 0.2032)
		(layer "F.Cu")
		(net "GND")
	)
	(segment
		(start 296.794682 -221.116652)
		(end 297.899582 -221.116652)
		(width 0.381)
		(layer "F.Cu")
		(net "GND")
	)
	(segment
		(start 379.896116 -280.242264)
		(end 379.895862 -280.778204)
		(width 0.254)
		(layer "F.Cu")
		(net "GND")
	)
	(segment
		(start 163.967414 -288.266632)
		(end 164.018214 -288.317432)
		(width 0.381)
		(layer "F.Cu")
		(net "GND")
	)
	(segment
		(start 132.315712 -216.78646)
		(end 132.315712 -216.250774)
		(width 0.254)
		(layer "F.Cu")
		(net "GND")
	)
	(segment
		(start 305.443382 -305.266598)
		(end 306.548282 -305.266598)
		(width 0.381)
		(layer "F.Cu")
		(net "GND")
	)
	(segment
		(start 281.707082 -202.416664)
		(end 282.811982 -202.416664)
		(width 0.381)
		(layer "F.Cu")
		(net "GND")
	)
	(segment
		(start 195.427346 -208.366614)
		(end 196.532246 -208.366614)
		(width 0.381)
		(layer "F.Cu")
		(net "GND")
	)
	(segment
		(start 428.279814 -236.416596)
		(end 429.384714 -236.416596)
		(width 0.381)
		(layer "F.Cu")
		(net "GND")
	)
	(segment
		(start 439.923682 -228.766624)
		(end 441.028582 -228.766624)
		(width 0.381)
		(layer "F.Cu")
		(net "GND")
	)
	(segment
		(start 443.367414 -229.616762)
		(end 444.472314 -229.616762)
		(width 0.381)
		(layer "F.Cu")
		(net "GND")
	)
	(segment
		(start 120.098312 -221.669864)
		(end 120.098312 -221.133924)
		(width 0.13208)
		(layer "F.Cu")
		(net "GND")
	)
	(segment
		(start 290.355782 -303.566576)
		(end 291.460682 -303.566576)
		(width 0.381)
		(layer "F.Cu")
		(net "GND")
	)
	(segment
		(start 132.425694 -271.289272)
		(end 132.425694 -271.825212)
		(width 0.2032)
		(layer "F.Cu")
		(net "GND")
	)
	(segment
		(start 193.088514 -250.866656)
		(end 191.983614 -250.866656)
		(width 0.381)
		(layer "F.Cu")
		(net "GND")
	)
	(segment
		(start 425.940982 -272.966688)
		(end 424.836082 -272.966688)
		(width 0.381)
		(layer "F.Cu")
		(net "GND")
	)
	(segment
		(start 454.798684 -111.291624)
		(end 451.81647 -111.291624)
		(width 0.3556)
		(layer "F.Cu")
		(net "GND")
	)
	(segment
		(start 256.080514 -281.466798)
		(end 257.185414 -281.466798)
		(width 0.381)
		(layer "F.Cu")
		(net "GND")
	)
	(segment
		(start 38.315646 -287.416748)
		(end 37.210746 -287.416748)
		(width 0.381)
		(layer "F.Cu")
		(net "GND")
	)
	(segment
		(start 181.444646 -313.766708)
		(end 180.339746 -313.766708)
		(width 0.381)
		(layer "F.Cu")
		(net "GND")
	)
	(segment
		(start 7.035546 -199.01662)
		(end 8.140446 -199.01662)
		(width 0.381)
		(layer "F.Cu")
		(net "GND")
	)
	(segment
		(start 334.200246 -245.540276)
		(end 334.205834 -245.545864)
		(width 0.2032)
		(layer "F.Cu")
		(net "GND")
	)
	(segment
		(start 104.121712 -216.78646)
		(end 104.121712 -216.250774)
		(width 0.254)
		(layer "F.Cu")
		(net "GND")
	)
	(segment
		(start 27.328114 -280.61666)
		(end 28.433014 -280.61666)
		(width 0.381)
		(layer "F.Cu")
		(net "GND")
	)
	(segment
		(start 348.772734 -243.644928)
		(end 348.77248 -243.644674)
		(width 0.254)
		(layer "F.Cu")
		(net "GND")
	)
	(segment
		(start 342.190578 -42.341546)
		(end 342.19134 -42.341546)
		(width 0.254)
		(layer "F.Cu")
		(net "GND")
	)
	(segment
		(start 200.632314 -202.416664)
		(end 201.737214 -202.416664)
		(width 0.381)
		(layer "F.Cu")
		(net "GND")
	)
	(segment
		(start 125.847094 -253.383796)
		(end 125.847094 -253.919482)
		(width 0.2032)
		(layer "F.Cu")
		(net "GND")
	)
	(segment
		(start 185.544714 -280.61666)
		(end 186.649614 -280.61666)
		(width 0.381)
		(layer "F.Cu")
		(net "GND")
	)
	(segment
		(start 136.655048 -262.336534)
		(end 136.654794 -262.872474)
		(width 0.254)
		(layer "F.Cu")
		(net "GND")
	)
	(segment
		(start 266.619482 -249.166634)
		(end 267.724382 -249.166634)
		(width 0.381)
		(layer "F.Cu")
		(net "GND")
	)
	(segment
		(start 415.402014 -287.213548)
		(end 415.198814 -287.416748)
		(width 0.381)
		(layer "F.Cu")
		(net "GND")
	)
	(segment
		(start 213.369398 -20.687792)
		(end 213.369398 -19.769328)
		(width 0.3556)
		(layer "F.Cu")
		(net "GND")
	)
	(segment
		(start 207.071214 -233.86669)
		(end 208.176114 -233.86669)
		(width 0.381)
		(layer "F.Cu")
		(net "GND")
	)
	(segment
		(start 260.180582 -235.566712)
		(end 261.285482 -235.566712)
		(width 0.381)
		(layer "F.Cu")
		(net "GND")
	)
	(segment
		(start 419.502082 -230.466646)
		(end 418.397182 -230.466646)
		(width 0.381)
		(layer "F.Cu")
		(net "GND")
	)
	(segment
		(start 14.579346 -283.166566)
		(end 15.684246 -283.166566)
		(width 0.381)
		(layer "F.Cu")
		(net "GND")
	)
	(segment
		(start 331.397102 -39.443152)
		(end 331.897482 -39.295324)
		(width 0.2032)
		(layer "F.Cu")
		(net "GND")
	)
	(segment
		(start 199.527414 -305.266598)
		(end 200.632314 -305.266598)
		(width 0.381)
		(layer "F.Cu")
		(net "GND")
	)
	(segment
		(start 381.775716 -286.7533)
		(end 381.775716 -287.288986)
		(width 0.254)
		(layer "F.Cu")
		(net "GND")
	)
	(segment
		(start 211.619846 -283.166566)
		(end 210.514946 -283.166566)
		(width 0.381)
		(layer "F.Cu")
		(net "GND")
	)
	(segment
		(start 63.942214 -308.666642)
		(end 65.047114 -308.666642)
		(width 0.381)
		(layer "F.Cu")
		(net "GND")
	)
	(segment
		(start 334.083406 -337.601306)
		(end 333.655416 -337.173316)
		(width 0.2032)
		(layer "F.Cu")
		(net "GND")
	)
	(segment
		(start 193.2178 -111.117888)
		(end 197.20687 -111.117888)
		(width 0.3556)
		(layer "F.Cu")
		(net "GND")
	)
	(segment
		(start 333.845662 -257.45313)
		(end 333.845662 -257.98907)
		(width 0.254)
		(layer "F.Cu")
		(net "GND")
	)
	(segment
		(start 297.899582 -239.81664)
		(end 299.004482 -239.81664)
		(width 0.381)
		(layer "F.Cu")
		(net "GND")
	)
	(segment
		(start 339.84438 -237.947454)
		(end 339.84438 -237.411514)
		(width 0.254)
		(layer "F.Cu")
		(net "GND")
	)
	(segment
		(start 115.106704 -357.91775)
		(end 115.716304 -357.91775)
		(width 0.381)
		(layer "F.Cu")
		(net "GND")
	)
	(segment
		(start 186.649614 -204.116686)
		(end 185.544714 -204.116686)
		(width 0.381)
		(layer "F.Cu")
		(net "GND")
	)
	(segment
		(start 425.940982 -266.1666)
		(end 427.045882 -266.1666)
		(width 0.381)
		(layer "F.Cu")
		(net "GND")
	)
	(segment
		(start 311.666382 -303.566576)
		(end 312.987182 -303.566576)
		(width 0.381)
		(layer "F.Cu")
		(net "GND")
	)
	(segment
		(start 103.762048 -287.288986)
		(end 103.761794 -287.28924)
		(width 0.254)
		(layer "F.Cu")
		(net "GND")
	)
	(segment
		(start 115.979448 -272.103342)
		(end 115.979194 -272.639282)
		(width 0.2032)
		(layer "F.Cu")
		(net "GND")
	)
	(segment
		(start 378.84608 -237.133638)
		(end 378.84608 -236.597952)
		(width 0.254)
		(layer "F.Cu")
		(net "GND")
	)
	(segment
		(start 263.624314 -279.766776)
		(end 264.729214 -279.766776)
		(width 0.381)
		(layer "F.Cu")
		(net "GND")
	)
	(segment
		(start 277.607014 -227.066602)
		(end 278.711914 -227.066602)
		(width 0.381)
		(layer "F.Cu")
		(net "GND")
	)
	(segment
		(start 301.343314 -246.616728)
		(end 302.448214 -246.616728)
		(width 0.381)
		(layer "F.Cu")
		(net "GND")
	)
	(segment
		(start 338.40039 -57.45734)
		(end 338.90077 -57.605168)
		(width 0.254)
		(layer "F.Cu")
		(net "GND")
	)
	(segment
		(start 452.016114 -238.966756)
		(end 450.911214 -238.966756)
		(width 0.381)
		(layer "F.Cu")
		(net "GND")
	)
	(segment
		(start 411.958282 -278.916638)
		(end 410.853382 -278.916638)
		(width 0.381)
		(layer "F.Cu")
		(net "GND")
	)
	(segment
		(start 443.367414 -234.716574)
		(end 444.472314 -234.716574)
		(width 0.381)
		(layer "F.Cu")
		(net "GND")
	)
	(segment
		(start 380.835916 -259.081016)
		(end 380.835916 -259.093462)
		(width 0.2032)
		(layer "F.Cu")
		(net "GND")
	)
	(segment
		(start 384.962654 -248.798588)
		(end 384.955034 -248.806208)
		(width 0.254)
		(layer "F.Cu")
		(net "GND")
	)
	(segment
		(start 290.355782 -291.666676)
		(end 289.250882 -291.666676)
		(width 0.381)
		(layer "F.Cu")
		(net "GND")
	)
	(segment
		(start 360.51998 -229.808786)
		(end 360.520234 -229.808532)
		(width 0.2032)
		(layer "F.Cu")
		(net "GND")
	)
	(segment
		(start 387.660896 -32.918908)
		(end 388.493 -32.918908)
		(width 0.3556)
		(layer "F.Cu")
		(net "GND")
	)
	(segment
		(start 20.889214 -216.866724)
		(end 19.784314 -216.866724)
		(width 0.381)
		(layer "F.Cu")
		(net "GND")
	)
	(segment
		(start 439.923682 -219.41663)
		(end 441.028582 -219.41663)
		(width 0.381)
		(layer "F.Cu")
		(net "GND")
	)
	(segment
		(start 194.193414 -213.46668)
		(end 193.088514 -213.46668)
		(width 0.381)
		(layer "F.Cu")
		(net "GND")
	)
	(segment
		(start 373.67718 -234.69219)
		(end 373.677434 -234.691936)
		(width 0.2032)
		(layer "F.Cu")
		(net "GND")
	)
	(segment
		(start 60.947046 -229.616762)
		(end 62.051946 -229.616762)
		(width 0.381)
		(layer "F.Cu")
		(net "GND")
	)
	(segment
		(start 383.655062 -261.244842)
		(end 383.655062 -260.708902)
		(width 0.2032)
		(layer "F.Cu")
		(net "GND")
	)
	(segment
		(start 42.415714 -230.466646)
		(end 41.310814 -230.466646)
		(width 0.381)
		(layer "F.Cu")
		(net "GND")
	)
	(segment
		(start 158.813246 -210.916774)
		(end 157.708346 -210.916774)
		(width 0.381)
		(layer "F.Cu")
		(net "GND")
	)
	(segment
		(start 63.942214 -241.516662)
		(end 65.047114 -241.516662)
		(width 0.381)
		(layer "F.Cu")
		(net "GND")
	)
	(segment
		(start 28.853638 -124.062236)
		(end 28.853638 -124.794264)
		(width 0.381)
		(layer "F.Cu")
		(net "GND")
	)
	(segment
		(start 405.050244 -55.759604)
		(end 404.406862 -55.759604)
		(width 0.3556)
		(layer "F.Cu")
		(net "GND")
	)
	(segment
		(start 106.111294 -279.428194)
		(end 106.111294 -279.96388)
		(width 0.254)
		(layer "F.Cu")
		(net "GND")
	)
	(segment
		(start 15.684246 -311.216802)
		(end 16.789146 -311.216802)
		(width 0.381)
		(layer "F.Cu")
		(net "GND")
	)
	(segment
		(start 418.885878 -174.396654)
		(end 418.408866 -173.919642)
		(width 0.2032)
		(layer "F.Cu")
		(net "GND")
	)
	(segment
		(start 414.297114 -298.466764)
		(end 415.402014 -298.466764)
		(width 0.381)
		(layer "F.Cu")
		(net "GND")
	)
	(segment
		(start 130.076448 -276.986492)
		(end 130.076448 -277.522432)
		(width 0.2032)
		(layer "F.Cu")
		(net "GND")
	)
	(segment
		(start 306.548282 -239.94364)
		(end 306.421282 -239.81664)
		(width 0.381)
		(layer "F.Cu")
		(net "GND")
	)
	(segment
		(start 197.637146 -296.766742)
		(end 196.532246 -296.766742)
		(width 0.381)
		(layer "F.Cu")
		(net "GND")
	)
	(segment
		(start 86.437216 -338.951316)
		(end 86.159594 -338.951316)
		(width 0.1778)
		(layer "F.Cu")
		(net "GND")
	)
	(segment
		(start 8.140446 -201.56678)
		(end 9.245346 -201.56678)
		(width 0.381)
		(layer "F.Cu")
		(net "GND")
	)
	(segment
		(start 418.180012 -182.555642)
		(end 417.834572 -182.210202)
		(width 0.2032)
		(layer "F.Cu")
		(net "GND")
	)
	(segment
		(start 325.922894 -343.451942)
		(end 326.246998 -343.451942)
		(width 0.2032)
		(layer "F.Cu")
		(net "GND")
	)
	(segment
		(start 115.399312 -223.297496)
		(end 115.399312 -222.76181)
		(width 0.254)
		(layer "F.Cu")
		(net "GND")
	)
	(segment
		(start 445.577214 -221.96679)
		(end 444.472314 -221.96679)
		(width 0.381)
		(layer "F.Cu")
		(net "GND")
	)
	(segment
		(start 114.39652 -27.367738)
		(end 114.39652 -26.580338)
		(width 0.3556)
		(layer "F.Cu")
		(net "GND")
	)
	(segment
		(start 154.093672 -52.068476)
		(end 154.801824 -52.068476)
		(width 0.2286)
		(layer "F.Cu")
		(net "GND")
	)
	(segment
		(start 103.291894 -277.800562)
		(end 103.291894 -278.336248)
		(width 0.254)
		(layer "F.Cu")
		(net "GND")
	)
	(segment
		(start 97.543112 -249.342148)
		(end 97.543366 -249.341894)
		(width 0.2032)
		(layer "F.Cu")
		(net "GND")
	)
	(segment
		(start 443.367414 -248.31675)
		(end 444.472314 -248.31675)
		(width 0.381)
		(layer "F.Cu")
		(net "GND")
	)
	(segment
		(start 444.472314 -195.616576)
		(end 443.367414 -195.616576)
		(width 0.381)
		(layer "F.Cu")
		(net "GND")
	)
	(segment
		(start 88.145366 -248.806208)
		(end 88.145366 -249.342148)
		(width 0.2032)
		(layer "F.Cu")
		(net "GND")
	)
	(segment
		(start 288.479992 -388.349998)
		(end 288.479992 -387.143498)
		(width 0.4572)
		(layer "F.Cu")
		(net "GND")
	)
	(segment
		(start 349.822516 -283.497782)
		(end 349.822516 -284.033468)
		(width 0.254)
		(layer "F.Cu")
		(net "GND")
	)
	(segment
		(start 38.83787 -354.022914)
		(end 38.443408 -353.628452)
		(width 0.2032)
		(layer "F.Cu")
		(net "GND")
	)
	(segment
		(start 97.543112 -230.900478)
		(end 97.543112 -231.436418)
		(width 0.2032)
		(layer "F.Cu")
		(net "GND")
	)
	(segment
		(start 119.268494 -285.939484)
		(end 119.268494 -286.47517)
		(width 0.254)
		(layer "F.Cu")
		(net "GND")
	)
	(segment
		(start 100.002848 -283.497782)
		(end 100.002848 -284.033468)
		(width 0.254)
		(layer "F.Cu")
		(net "GND")
	)
	(segment
		(start 184.439814 -196.466714)
		(end 185.544714 -196.466714)
		(width 0.381)
		(layer "F.Cu")
		(net "GND")
	)
	(segment
		(start 96.243648 -275.35886)
		(end 96.243648 -275.894546)
		(width 0.2032)
		(layer "F.Cu")
		(net "GND")
	)
	(segment
		(start 180.555646 -112.97539)
		(end 180.955696 -112.57534)
		(width 0.3556)
		(layer "F.Cu")
		(net "GND")
	)
	(segment
		(start 166.357046 -306.116736)
		(end 165.252146 -306.116736)
		(width 0.381)
		(layer "F.Cu")
		(net "GND")
	)
	(segment
		(start 121.618248 -287.288986)
		(end 121.617994 -287.28924)
		(width 0.254)
		(layer "F.Cu")
		(net "GND")
	)
	(segment
		(start 219.94495 -49.911)
		(end 219.94495 -48.79975)
		(width 0.3556)
		(layer "F.Cu")
		(net "GND")
	)
	(segment
		(start 340.784434 -244.45849)
		(end 340.784434 -243.922804)
		(width 0.2032)
		(layer "F.Cu")
		(net "GND")
	)
	(segment
		(start 256.506218 -48.866298)
		(end 255.261618 -48.866298)
		(width 0.17272)
		(layer "F.Cu")
		(net "GND")
	)
	(segment
		(start 48.854614 -295.916604)
		(end 49.959514 -295.916604)
		(width 0.381)
		(layer "F.Cu")
		(net "GND")
	)
	(segment
		(start 328.801984 -21.625052)
		(end 329.548744 -21.625052)
		(width 0.3556)
		(layer "F.Cu")
		(net "GND")
	)
	(segment
		(start 60.947046 -313.766708)
		(end 62.267846 -313.766708)
		(width 0.381)
		(layer "F.Cu")
		(net "GND")
	)
	(segment
		(start 15.684246 -304.416714)
		(end 16.789146 -304.416714)
		(width 0.381)
		(layer "F.Cu")
		(net "GND")
	)
	(segment
		(start 173.900846 -301.866808)
		(end 175.005746 -301.866808)
		(width 0.381)
		(layer "F.Cu")
		(net "GND")
	)
	(segment
		(start 52.298346 -240.666778)
		(end 53.403246 -240.666778)
		(width 0.381)
		(layer "F.Cu")
		(net "GND")
	)
	(segment
		(start 278.711914 -195.616576)
		(end 277.607014 -195.616576)
		(width 0.381)
		(layer "F.Cu")
		(net "GND")
	)
	(segment
		(start 286.255714 -287.416748)
		(end 287.360614 -287.416748)
		(width 0.381)
		(layer "F.Cu")
		(net "GND")
	)
	(segment
		(start 345.123516 -283.497782)
		(end 345.123516 -284.033468)
		(width 0.254)
		(layer "F.Cu")
		(net "GND")
	)
	(segment
		(start 295.352724 -362.856018)
		(end 295.352724 -362.390182)
		(width 0.2032)
		(layer "F.Cu")
		(net "GND")
	)
	(segment
		(start 337.604862 -278.614378)
		(end 337.604608 -279.14981)
		(width 0.2032)
		(layer "F.Cu")
		(net "GND")
	)
	(segment
		(start 410.853382 -299.316648)
		(end 411.958282 -299.316648)
		(width 0.381)
		(layer "F.Cu")
		(net "GND")
	)
	(segment
		(start 307.782214 -197.316598)
		(end 308.887114 -197.316598)
		(width 0.381)
		(layer "F.Cu")
		(net "GND")
	)
	(segment
		(start 452.016114 -267.016738)
		(end 450.911214 -267.016738)
		(width 0.381)
		(layer "F.Cu")
		(net "GND")
	)
	(segment
		(start 336.195162 -262.058658)
		(end 336.195162 -261.522718)
		(width 0.2032)
		(layer "F.Cu")
		(net "GND")
	)
	(segment
		(start 262.519414 -261.916672)
		(end 263.624314 -261.916672)
		(width 0.381)
		(layer "F.Cu")
		(net "GND")
	)
	(segment
		(start 360.990134 -215.972644)
		(end 360.990134 -215.436958)
		(width 0.2032)
		(layer "F.Cu")
		(net "GND")
	)
	(segment
		(start 266.619482 -295.916604)
		(end 267.724382 -295.916604)
		(width 0.381)
		(layer "F.Cu")
		(net "GND")
	)
	(segment
		(start 358.170734 -240.389156)
		(end 358.170734 -239.853216)
		(width 0.254)
		(layer "F.Cu")
		(net "GND")
	)
	(segment
		(start 433.484782 -233.86669)
		(end 434.589682 -233.86669)
		(width 0.381)
		(layer "F.Cu")
		(net "GND")
	)
	(segment
		(start 464.764882 -306.96662)
		(end 463.659982 -306.96662)
		(width 0.381)
		(layer "F.Cu")
		(net "GND")
	)
	(segment
		(start 188.988446 -217.716608)
		(end 187.883546 -217.716608)
		(width 0.381)
		(layer "F.Cu")
		(net "GND")
	)
	(segment
		(start 300.238414 -244.916706)
		(end 301.343314 -244.916706)
		(width 0.381)
		(layer "F.Cu")
		(net "GND")
	)
	(segment
		(start 7.035546 -223.666558)
		(end 8.140446 -223.666558)
		(width 0.381)
		(layer "F.Cu")
		(net "GND")
	)
	(segment
		(start 182.549546 -304.416714)
		(end 181.444646 -304.416714)
		(width 0.381)
		(layer "F.Cu")
		(net "GND")
	)
	(segment
		(start 57.503314 -303.566576)
		(end 58.608214 -303.566576)
		(width 0.381)
		(layer "F.Cu")
		(net "GND")
	)
	(segment
		(start 123.027694 -261.522718)
		(end 123.027694 -262.058658)
		(width 0.2032)
		(layer "F.Cu")
		(net "GND")
	)
	(segment
		(start 91.904312 -228.1809)
		(end 91.904312 -227.64496)
		(width 0.2032)
		(layer "F.Cu")
		(net "GND")
	)
	(segment
		(start 345.593162 -277.800562)
		(end 345.593162 -278.336248)
		(width 0.254)
		(layer "F.Cu")
		(net "GND")
	)
	(segment
		(start 125.737366 -234.691936)
		(end 125.737366 -234.15625)
		(width 0.2032)
		(layer "F.Cu")
		(net "GND")
	)
	(segment
		(start 114.459766 -226.017328)
		(end 114.459766 -226.553268)
		(width 0.254)
		(layer "F.Cu")
		(net "GND")
	)
	(segment
		(start 125.737366 -220.041724)
		(end 125.737366 -219.506038)
		(width 0.254)
		(layer "F.Cu")
		(net "GND")
	)
	(segment
		(start 429.384714 -267.016738)
		(end 430.489614 -267.016738)
		(width 0.381)
		(layer "F.Cu")
		(net "GND")
	)
	(segment
		(start 425.940982 -310.366664)
		(end 424.836082 -310.366664)
		(width 0.381)
		(layer "F.Cu")
		(net "GND")
	)
	(segment
		(start 272.273014 -290.816792)
		(end 271.168114 -290.816792)
		(width 0.381)
		(layer "F.Cu")
		(net "GND")
	)
	(segment
		(start 342.304116 -286.7533)
		(end 342.304116 -287.288986)
		(width 0.254)
		(layer "F.Cu")
		(net "GND")
	)
	(segment
		(start 211.619846 -225.36658)
		(end 212.724746 -225.36658)
		(width 0.381)
		(layer "F.Cu")
		(net "GND")
	)
	(segment
		(start 393.046966 -8.320024)
		(end 393.046966 -9.424924)
		(width 0.3556)
		(layer "F.Cu")
		(net "GND")
	)
	(segment
		(start 43.520614 -291.666676)
		(end 42.415714 -291.666676)
		(width 0.381)
		(layer "F.Cu")
		(net "GND")
	)
	(segment
		(start 108.45673 -60.086748)
		(end 109.06633 -60.086748)
		(width 0.3556)
		(layer "F.Cu")
		(net "GND")
	)
	(segment
		(start 94.833694 -271.289272)
		(end 94.833948 -271.289526)
		(width 0.2032)
		(layer "F.Cu")
		(net "GND")
	)
	(segment
		(start 178.000914 -295.916604)
		(end 179.105814 -295.916604)
		(width 0.381)
		(layer "F.Cu")
		(net "GND")
	)
	(segment
		(start 413.192214 -242.3668)
		(end 414.297114 -242.3668)
		(width 0.381)
		(layer "F.Cu")
		(net "GND")
	)
	(segment
		(start 98.123248 -254.197612)
		(end 98.123248 -254.733552)
		(width 0.2032)
		(layer "F.Cu")
		(net "GND")
	)
	(segment
		(start 435.823614 -248.31675)
		(end 436.928514 -248.31675)
		(width 0.381)
		(layer "F.Cu")
		(net "GND")
	)
	(segment
		(start 195.427346 -258.516628)
		(end 196.532246 -258.516628)
		(width 0.381)
		(layer "F.Cu")
		(net "GND")
	)
	(segment
		(start 126.207266 -238.761524)
		(end 126.207266 -238.225584)
		(width 0.2032)
		(layer "F.Cu")
		(net "GND")
	)
	(segment
		(start 98.60788 -414.376616)
		(end 98.6028 -414.371536)
		(width 0.3556)
		(layer "F.Cu")
		(net "GND")
	)
	(segment
		(start 368.97818 -216.250774)
		(end 368.978434 -216.25052)
		(width 0.254)
		(layer "F.Cu")
		(net "GND")
	)
	(segment
		(start 178.000914 -277.216616)
		(end 179.105814 -277.216616)
		(width 0.381)
		(layer "F.Cu")
		(net "GND")
	)
	(segment
		(start 7.035546 -311.216802)
		(end 8.140446 -311.216802)
		(width 0.381)
		(layer "F.Cu")
		(net "GND")
	)
	(segment
		(start 453.121014 -260.21665)
		(end 452.016114 -260.21665)
		(width 0.381)
		(layer "F.Cu")
		(net "GND")
	)
	(segment
		(start 280.786078 -424.94835)
		(end 280.271474 -424.94835)
		(width 0.3556)
		(layer "F.Cu")
		(net "GND")
	)
	(segment
		(start 441.028582 -282.316682)
		(end 442.133482 -282.316682)
		(width 0.381)
		(layer "F.Cu")
		(net "GND")
	)
	(segment
		(start 124.327666 -230.086916)
		(end 124.327412 -230.086662)
		(width 0.2032)
		(layer "F.Cu")
		(net "GND")
	)
	(segment
		(start 43.520614 -241.516662)
		(end 42.415714 -241.516662)
		(width 0.381)
		(layer "F.Cu")
		(net "GND")
	)
	(segment
		(start 27.328114 -207.51673)
		(end 28.433014 -207.51673)
		(width 0.381)
		(layer "F.Cu")
		(net "GND")
	)
	(segment
		(start 29.666946 -281.466798)
		(end 30.771846 -281.466798)
		(width 0.381)
		(layer "F.Cu")
		(net "GND")
	)
	(segment
		(start 345.013534 -235.506006)
		(end 345.013534 -234.970066)
		(width 0.2032)
		(layer "F.Cu")
		(net "GND")
	)
	(segment
		(start 353.242626 -239.169448)
		(end 353.119436 -239.292638)
		(width 0.254)
		(layer "F.Cu")
		(net "GND")
	)
	(segment
		(start 418.397182 -305.266598)
		(end 417.292282 -305.266598)
		(width 0.381)
		(layer "F.Cu")
		(net "GND")
	)
	(segment
		(start 375.55678 -216.78646)
		(end 375.55678 -216.250774)
		(width 0.254)
		(layer "F.Cu")
		(net "GND")
	)
	(segment
		(start 435.823614 -304.416714)
		(end 436.928514 -304.416714)
		(width 0.381)
		(layer "F.Cu")
		(net "GND")
	)
	(segment
		(start 421.927528 -157.590236)
		(end 422.58488 -157.590236)
		(width 0.381)
		(layer "F.Cu")
		(net "GND")
	)
	(segment
		(start 124.327666 -237.133892)
		(end 124.327412 -237.133638)
		(width 0.254)
		(layer "F.Cu")
		(net "GND")
	)
	(segment
		(start 12.240514 -244.066568)
		(end 13.345414 -244.066568)
		(width 0.381)
		(layer "F.Cu")
		(net "GND")
	)
	(segment
		(start 298.754292 -344.700352)
		(end 299.6946 -344.700352)
		(width 0.508)
		(layer "F.Cu")
		(net "GND")
	)
	(segment
		(start 185.544714 -207.51673)
		(end 184.439814 -207.51673)
		(width 0.381)
		(layer "F.Cu")
		(net "GND")
	)
	(segment
		(start 118.218712 -223.297496)
		(end 118.218712 -222.76181)
		(width 0.254)
		(layer "F.Cu")
		(net "GND")
	)
	(segment
		(start 105.15473 -338.86013)
		(end 104.677972 -338.86013)
		(width 0.381)
		(layer "F.Cu")
		(net "GND")
	)
	(segment
		(start 44.754546 -296.766742)
		(end 45.859446 -296.766742)
		(width 0.381)
		(layer "F.Cu")
		(net "GND")
	)
	(segment
		(start 376.606562 -274.54479)
		(end 376.606816 -275.08073)
		(width 0.2032)
		(layer "F.Cu")
		(net "GND")
	)
	(segment
		(start 304.135282 -235.566712)
		(end 305.443382 -235.566712)
		(width 0.381)
		(layer "F.Cu")
		(net "GND")
	)
	(segment
		(start 96.791272 -425.405296)
		(end 96.689672 -425.303696)
		(width 0.3556)
		(layer "F.Cu")
		(net "GND")
	)
	(segment
		(start 418.397182 -261.066788)
		(end 417.292282 -261.066788)
		(width 0.381)
		(layer "F.Cu")
		(net "GND")
	)
	(segment
		(start 96.133412 -242.016788)
		(end 96.133412 -241.481102)
		(width 0.2032)
		(layer "F.Cu")
		(net "GND")
	)
	(segment
		(start 352.641916 -285.6611)
		(end 352.641662 -285.661354)
		(width 0.254)
		(layer "F.Cu")
		(net "GND")
	)
	(segment
		(start 7.035546 -242.3668)
		(end 8.140446 -242.3668)
		(width 0.381)
		(layer "F.Cu")
		(net "GND")
	)
	(segment
		(start 410.853382 -262.76681)
		(end 411.958282 -262.76681)
		(width 0.381)
		(layer "F.Cu")
		(net "GND")
	)
	(segment
		(start 386.02412 -282.703524)
		(end 386.02412 -283.200602)
		(width 0.254)
		(layer "F.Cu")
		(net "GND")
	)
	(segment
		(start 87.675466 -233.87812)
		(end 87.675466 -233.34218)
		(width 0.254)
		(layer "F.Cu")
		(net "GND")
	)
	(segment
		(start 356.400862 -278.614632)
		(end 356.400862 -279.150318)
		(width 0.254)
		(layer "F.Cu")
		(net "GND")
	)
	(segment
		(start 30.771846 -225.36658)
		(end 31.876746 -225.36658)
		(width 0.381)
		(layer "F.Cu")
		(net "GND")
	)
	(segment
		(start 22.123146 -296.766742)
		(end 23.228046 -296.766742)
		(width 0.381)
		(layer "F.Cu")
		(net "GND")
	)
	(segment
		(start 418.408866 -165.283642)
		(end 418.180012 -165.283642)
		(width 0.2032)
		(layer "F.Cu")
		(net "GND")
	)
	(segment
		(start 162.913314 -312.91657)
		(end 161.642552 -312.91657)
		(width 0.381)
		(layer "F.Cu")
		(net "GND")
	)
	(segment
		(start 170.457114 -262.76681)
		(end 171.562014 -262.76681)
		(width 0.381)
		(layer "F.Cu")
		(net "GND")
	)
	(segment
		(start 170.457114 -258.516628)
		(end 171.562014 -258.516628)
		(width 0.381)
		(layer "F.Cu")
		(net "GND")
	)
	(segment
		(start 424.836082 -245.76659)
		(end 425.940982 -245.76659)
		(width 0.381)
		(layer "F.Cu")
		(net "GND")
	)
	(segment
		(start 418.397182 -308.666642)
		(end 417.292282 -308.666642)
		(width 0.381)
		(layer "F.Cu")
		(net "GND")
	)
	(segment
		(start 115.399312 -216.78646)
		(end 115.399312 -216.25052)
		(width 0.254)
		(layer "F.Cu")
		(net "GND")
	)
	(segment
		(start 178.78552 -424.64736)
		(end 178.78552 -423.96156)
		(width 0.3556)
		(layer "F.Cu")
		(net "GND")
	)
	(segment
		(start 195.427346 -234.716574)
		(end 196.532246 -234.716574)
		(width 0.381)
		(layer "F.Cu")
		(net "GND")
	)
	(segment
		(start 86.375494 -269.66164)
		(end 85.905594 -269.38351)
		(width 0.254)
		(layer "F.Cu")
		(net "GND")
	)
	(segment
		(start 126.786894 -259.894832)
		(end 126.786894 -260.430772)
		(width 0.2032)
		(layer "F.Cu")
		(net "GND")
	)
	(segment
		(start 87.315294 -259.894832)
		(end 87.785194 -259.616956)
		(width 0.254)
		(layer "F.Cu")
		(net "GND")
	)
	(segment
		(start 367.568734 -222.48368)
		(end 367.568734 -221.94774)
		(width 0.254)
		(layer "F.Cu")
		(net "GND")
	)
	(segment
		(start 93.783912 -242.295172)
		(end 93.784166 -242.294918)
		(width 0.2032)
		(layer "F.Cu")
		(net "GND")
	)
	(segment
		(start 49.959514 -278.916638)
		(end 51.064414 -278.916638)
		(width 0.381)
		(layer "F.Cu")
		(net "GND")
	)
	(segment
		(start 181.444646 -233.016806)
		(end 182.549546 -233.016806)
		(width 0.381)
		(layer "F.Cu")
		(net "GND")
	)
	(segment
		(start 33.767014 -250.866656)
		(end 34.871914 -250.866656)
		(width 0.381)
		(layer "F.Cu")
		(net "GND")
	)
	(segment
		(start 368.618516 -278.614378)
		(end 368.618516 -279.150318)
		(width 0.254)
		(layer "F.Cu")
		(net "GND")
	)
	(segment
		(start 316.375796 -59.446668)
		(end 316.523116 -59.299348)
		(width 0.381)
		(layer "F.Cu")
		(net "GND")
	)
	(segment
		(start 23.228046 -273.816572)
		(end 24.332946 -273.816572)
		(width 0.381)
		(layer "F.Cu")
		(net "GND")
	)
	(segment
		(start 100.362512 -228.1809)
		(end 100.362766 -228.180646)
		(width 0.2032)
		(layer "F.Cu")
		(net "GND")
	)
	(segment
		(start 448.572382 -230.466646)
		(end 447.467482 -230.466646)
		(width 0.381)
		(layer "F.Cu")
		(net "GND")
	)
	(segment
		(start 376.96648 -233.877866)
		(end 376.96648 -233.34218)
		(width 0.2032)
		(layer "F.Cu")
		(net "GND")
	)
	(segment
		(start 179.105814 -200.716642)
		(end 178.000914 -200.716642)
		(width 0.381)
		(layer "F.Cu")
		(net "GND")
	)
	(segment
		(start 412.465774 -29.877258)
		(end 413.120332 -29.877258)
		(width 0.3556)
		(layer "F.Cu")
		(net "GND")
	)
	(segment
		(start 179.105814 -213.46668)
		(end 178.000914 -213.46668)
		(width 0.381)
		(layer "F.Cu")
		(net "GND")
	)
	(segment
		(start 278.3586 -418.338)
		(end 278.474678 -418.454078)
		(width 0.3556)
		(layer "F.Cu")
		(net "GND")
	)
	(segment
		(start 347.36278 -244.458744)
		(end 347.363034 -244.45849)
		(width 0.2032)
		(layer "F.Cu")
		(net "GND")
	)
	(segment
		(start 14.579346 -201.56678)
		(end 15.684246 -201.56678)
		(width 0.381)
		(layer "F.Cu")
		(net "GND")
	)
	(segment
		(start 436.928514 -296.766742)
		(end 438.033414 -296.766742)
		(width 0.381)
		(layer "F.Cu")
		(net "GND")
	)
	(segment
		(start 339.84438 -226.553268)
		(end 339.84438 -226.017582)
		(width 0.254)
		(layer "F.Cu")
		(net "GND")
	)
	(segment
		(start 173.900846 -225.36658)
		(end 172.795946 -225.36658)
		(width 0.381)
		(layer "F.Cu")
		(net "GND")
	)
	(segment
		(start 448.572382 -245.76659)
		(end 447.467482 -245.76659)
		(width 0.381)
		(layer "F.Cu")
		(net "GND")
	)
	(segment
		(start 341.902034 -57.605168)
		(end 340.901782 -57.605168)
		(width 0.2032)
		(layer "F.Cu")
		(net "GND")
	)
	(segment
		(start 266.619482 -271.266666)
		(end 267.724382 -271.266666)
		(width 0.381)
		(layer "F.Cu")
		(net "GND")
	)
	(segment
		(start 157.48762 -47.950628)
		(end 157.831028 -47.60722)
		(width 0.3556)
		(layer "F.Cu")
		(net "GND")
	)
	(segment
		(start 122.448066 -242.017042)
		(end 122.448066 -241.481102)
		(width 0.254)
		(layer "F.Cu")
		(net "GND")
	)
	(segment
		(start 372.267734 -237.133892)
		(end 372.26748 -237.133638)
		(width 0.254)
		(layer "F.Cu")
		(net "GND")
	)
	(segment
		(start 363.33938 -216.78646)
		(end 363.33938 -216.25052)
		(width 0.254)
		(layer "F.Cu")
		(net "GND")
	)
	(segment
		(start 166.357046 -315.46673)
		(end 167.461946 -315.46673)
		(width 0.381)
		(layer "F.Cu")
		(net "GND")
	)
	(segment
		(start 179.105814 -266.1666)
		(end 178.000914 -266.1666)
		(width 0.381)
		(layer "F.Cu")
		(net "GND")
	)
	(segment
		(start 125.377448 -282.405582)
		(end 125.377194 -282.405836)
		(width 0.254)
		(layer "F.Cu")
		(net "GND")
	)
	(segment
		(start 175.005746 -225.36658)
		(end 173.900846 -225.36658)
		(width 0.381)
		(layer "F.Cu")
		(net "GND")
	)
	(segment
		(start 173.900846 -311.216802)
		(end 175.208946 -311.216802)
		(width 0.381)
		(layer "F.Cu")
		(net "GND")
	)
	(segment
		(start 436.928514 -313.766708)
		(end 438.033414 -313.766708)
		(width 0.381)
		(layer "F.Cu")
		(net "GND")
	)
	(segment
		(start 43.520614 -233.86669)
		(end 42.415714 -233.86669)
		(width 0.381)
		(layer "F.Cu")
		(net "GND")
	)
	(segment
		(start 187.883546 -309.51678)
		(end 188.988446 -309.51678)
		(width 0.381)
		(layer "F.Cu")
		(net "GND")
	)
	(segment
		(start 164.018214 -250.866656)
		(end 162.913314 -250.866656)
		(width 0.381)
		(layer "F.Cu")
		(net "GND")
	)
	(segment
		(start 263.624314 -317.166752)
		(end 264.729214 -317.166752)
		(width 0.381)
		(layer "F.Cu")
		(net "GND")
	)
	(segment
		(start 127.147066 -214.344758)
		(end 127.147066 -213.732618)
		(width 0.254)
		(layer "F.Cu")
		(net "GND")
	)
	(segment
		(start 405.648414 -301.866808)
		(end 406.753314 -301.866808)
		(width 0.381)
		(layer "F.Cu")
		(net "GND")
	)
	(segment
		(start 27.328114 -312.91657)
		(end 28.433014 -312.91657)
		(width 0.381)
		(layer "F.Cu")
		(net "GND")
	)
	(segment
		(start 8.140446 -260.21665)
		(end 9.245346 -260.21665)
		(width 0.381)
		(layer "F.Cu")
		(net "GND")
	)
	(segment
		(start 364.27918 -216.250774)
		(end 364.279434 -216.25052)
		(width 0.254)
		(layer "F.Cu")
		(net "GND")
	)
	(segment
		(start 171.562014 -306.96662)
		(end 170.457114 -306.96662)
		(width 0.381)
		(layer "F.Cu")
		(net "GND")
	)
	(segment
		(start 208.176114 -196.466714)
		(end 209.281014 -196.466714)
		(width 0.381)
		(layer "F.Cu")
		(net "GND")
	)
	(segment
		(start 444.472314 -251.716794)
		(end 445.577214 -251.716794)
		(width 0.381)
		(layer "F.Cu")
		(net "GND")
	)
	(segment
		(start 12.240514 -316.316614)
		(end 11.135614 -316.316614)
		(width 0.381)
		(layer "F.Cu")
		(net "GND")
	)
	(segment
		(start 19.784314 -247.466612)
		(end 20.889214 -247.466612)
		(width 0.381)
		(layer "F.Cu")
		(net "GND")
	)
	(segment
		(start 48.854614 -222.816674)
		(end 49.959514 -222.816674)
		(width 0.381)
		(layer "F.Cu")
		(net "GND")
	)
	(segment
		(start 68.522088 -55.578756)
		(end 68.522088 -56.09463)
		(width 0.254)
		(layer "F.Cu")
		(net "GND")
	)
	(segment
		(start 100.832666 -246.900446)
		(end 100.832666 -246.364506)
		(width 0.2032)
		(layer "F.Cu")
		(net "GND")
	)
	(segment
		(start 414.297114 -283.166566)
		(end 415.402014 -283.166566)
		(width 0.381)
		(layer "F.Cu")
		(net "GND")
	)
	(segment
		(start 413.192214 -238.966756)
		(end 414.297114 -238.966756)
		(width 0.381)
		(layer "F.Cu")
		(net "GND")
	)
	(segment
		(start 119.738648 -267.219938)
		(end 119.738394 -267.755878)
		(width 0.254)
		(layer "F.Cu")
		(net "GND")
	)
	(segment
		(start 290.355782 -238.116618)
		(end 291.460682 -238.116618)
		(width 0.381)
		(layer "F.Cu")
		(net "GND")
	)
	(segment
		(start 63.942214 -299.316648)
		(end 65.047114 -299.316648)
		(width 0.381)
		(layer "F.Cu")
		(net "GND")
	)
	(segment
		(start 56.398414 -211.766658)
		(end 57.503314 -211.766658)
		(width 0.381)
		(layer "F.Cu")
		(net "GND")
	)
	(segment
		(start 137.484866 -250.155964)
		(end 138.107166 -250.155964)
		(width 0.254)
		(layer "F.Cu")
		(net "GND")
	)
	(segment
		(start 372.267734 -243.644928)
		(end 372.26748 -243.644674)
		(width 0.2032)
		(layer "F.Cu")
		(net "GND")
	)
	(segment
		(start 165.252146 -251.716794)
		(end 166.357046 -251.716794)
		(width 0.381)
		(layer "F.Cu")
		(net "GND")
	)
	(segment
		(start 112.579912 -226.017582)
		(end 112.580166 -226.017328)
		(width 0.254)
		(layer "F.Cu")
		(net "GND")
	)
	(segment
		(start 27.328114 -286.56661)
		(end 28.433014 -286.56661)
		(width 0.381)
		(layer "F.Cu")
		(net "GND")
	)
	(segment
		(start 93.784166 -237.947454)
		(end 93.784166 -237.411514)
		(width 0.254)
		(layer "F.Cu")
		(net "GND")
	)
	(segment
		(start 130.906012 -228.994716)
		(end 130.906012 -228.45903)
		(width 0.2032)
		(layer "F.Cu")
		(net "GND")
	)
	(segment
		(start 371.437916 -286.7533)
		(end 371.437916 -287.288986)
		(width 0.254)
		(layer "F.Cu")
		(net "GND")
	)
	(segment
		(start 363.33938 -226.017582)
		(end 363.339634 -226.017328)
		(width 0.254)
		(layer "F.Cu")
		(net "GND")
	)
	(segment
		(start 429.384714 -272.116804)
		(end 430.489614 -272.116804)
		(width 0.381)
		(layer "F.Cu")
		(net "GND")
	)
	(segment
		(start 335.14538 -217.87866)
		(end 335.145126 -217.878406)
		(width 0.2032)
		(layer "F.Cu")
		(net "GND")
	)
	(segment
		(start 170.63593 -440.019948)
		(end 171.24553 -440.019948)
		(width 0.3556)
		(layer "F.Cu")
		(net "GND")
	)
	(segment
		(start 132.895848 -256.361184)
		(end 132.895594 -256.361438)
		(width 0.254)
		(layer "F.Cu")
		(net "GND")
	)
	(segment
		(start 439.923682 -294.216582)
		(end 441.028582 -294.216582)
		(width 0.381)
		(layer "F.Cu")
		(net "GND")
	)
	(segment
		(start 445.577214 -206.666592)
		(end 444.472314 -206.666592)
		(width 0.381)
		(layer "F.Cu")
		(net "GND")
	)
	(segment
		(start 108.820712 -232.528618)
		(end 108.820966 -232.528364)
		(width 0.254)
		(layer "F.Cu")
		(net "GND")
	)
	(segment
		(start 463.659982 -230.466646)
		(end 464.764882 -230.466646)
		(width 0.381)
		(layer "F.Cu")
		(net "GND")
	)
	(segment
		(start 131.016248 -264.499852)
		(end 131.015994 -264.500106)
		(width 0.2032)
		(layer "F.Cu")
		(net "GND")
	)
	(segment
		(start 312.987182 -295.916604)
		(end 314.092082 -295.916604)
		(width 0.381)
		(layer "F.Cu")
		(net "GND")
	)
	(segment
		(start 418.397182 -233.86669)
		(end 417.292282 -233.86669)
		(width 0.381)
		(layer "F.Cu")
		(net "GND")
	)
	(segment
		(start 413.192214 -292.516814)
		(end 414.297114 -292.516814)
		(width 0.381)
		(layer "F.Cu")
		(net "GND")
	)
	(segment
		(start 452.016114 -221.96679)
		(end 450.911214 -221.96679)
		(width 0.381)
		(layer "F.Cu")
		(net "GND")
	)
	(segment
		(start 312.987182 -308.666642)
		(end 314.092082 -308.666642)
		(width 0.381)
		(layer "F.Cu")
		(net "GND")
	)
	(segment
		(start 286.058864 -363.25048)
		(end 285.664402 -362.856018)
		(width 0.2032)
		(layer "F.Cu")
		(net "GND")
	)
	(segment
		(start 387.633972 -28.70962)
		(end 386.82168 -28.70962)
		(width 0.3556)
		(layer "F.Cu")
		(net "GND")
	)
	(segment
		(start 132.785866 -246.900446)
		(end 132.785612 -246.900192)
		(width 0.2032)
		(layer "F.Cu")
		(net "GND")
	)
	(segment
		(start 44.754546 -278.066754)
		(end 45.859446 -278.066754)
		(width 0.381)
		(layer "F.Cu")
		(net "GND")
	)
	(segment
		(start 130.906266 -233.87812)
		(end 130.906012 -233.877866)
		(width 0.2032)
		(layer "F.Cu")
		(net "GND")
	)
	(segment
		(start 405.648414 -265.316716)
		(end 406.753314 -265.316716)
		(width 0.381)
		(layer "F.Cu")
		(net "GND")
	)
	(segment
		(start 293.799514 -317.166752)
		(end 294.904414 -317.166752)
		(width 0.381)
		(layer "F.Cu")
		(net "GND")
	)
	(segment
		(start 210.514946 -233.016806)
		(end 211.619846 -233.016806)
		(width 0.381)
		(layer "F.Cu")
		(net "GND")
	)
	(segment
		(start 346.149422 -36.896548)
		(end 345.904058 -37.141912)
		(width 0.254)
		(layer "F.Cu")
		(net "GND")
	)
	(segment
		(start 344.183716 -265.592306)
		(end 344.183462 -265.592306)
		(width 0.254)
		(layer "F.Cu")
		(net "GND")
	)
	(segment
		(start 365.21898 -222.76181)
		(end 365.219234 -222.761556)
		(width 0.254)
		(layer "F.Cu")
		(net "GND")
	)
	(segment
		(start 7.035546 -206.666592)
		(end 8.140446 -206.666592)
		(width 0.381)
		(layer "F.Cu")
		(net "GND")
	)
	(segment
		(start 341.37727 -51.269646)
		(end 341.37727 -50.329846)
		(width 0.2032)
		(layer "F.Cu")
		(net "GND")
	)
	(segment
		(start 207.071214 -239.81664)
		(end 208.176114 -239.81664)
		(width 0.381)
		(layer "F.Cu")
		(net "GND")
	)
	(segment
		(start 29.666946 -317.166752)
		(end 30.771846 -317.166752)
		(width 0.381)
		(layer "F.Cu")
		(net "GND")
	)
	(segment
		(start 413.192214 -263.616694)
		(end 414.297114 -263.616694)
		(width 0.381)
		(layer "F.Cu")
		(net "GND")
	)
	(segment
		(start 406.753314 -206.666592)
		(end 408.11069 -206.666592)
		(width 0.381)
		(layer "F.Cu")
		(net "GND")
	)
	(segment
		(start 271.168114 -233.016806)
		(end 270.063214 -233.016806)
		(width 0.381)
		(layer "F.Cu")
		(net "GND")
	)
	(segment
		(start 77.497178 -145.455132)
		(end 76.999338 -145.455132)
		(width 0.3556)
		(layer "F.Cu")
		(net "GND")
	)
	(segment
		(start 100.362512 -242.830858)
		(end 100.362512 -242.295172)
		(width 0.254)
		(layer "F.Cu")
		(net "GND")
	)
	(segment
		(start 375.087134 -217.600276)
		(end 375.087134 -217.064336)
		(width 0.254)
		(layer "F.Cu")
		(net "GND")
	)
	(segment
		(start 158.813246 -203.266802)
		(end 157.694884 -203.266802)
		(width 0.381)
		(layer "F.Cu")
		(net "GND")
	)
	(segment
		(start 96.243648 -261.244588)
		(end 96.243394 -261.244842)
		(width 0.2032)
		(layer "F.Cu")
		(net "GND")
	)
	(segment
		(start 435.823614 -283.166566)
		(end 436.928514 -283.166566)
		(width 0.381)
		(layer "F.Cu")
		(net "GND")
	)
	(segment
		(start 172.795946 -313.766708)
		(end 173.900846 -313.766708)
		(width 0.381)
		(layer "F.Cu")
		(net "GND")
	)
	(segment
		(start 289.250882 -213.46668)
		(end 290.355782 -213.46668)
		(width 0.381)
		(layer "F.Cu")
		(net "GND")
	)
	(segment
		(start 293.799514 -225.36658)
		(end 292.694614 -225.36658)
		(width 0.381)
		(layer "F.Cu")
		(net "GND")
	)
	(segment
		(start 200.632314 -277.216616)
		(end 201.737214 -277.216616)
		(width 0.381)
		(layer "F.Cu")
		(net "GND")
	)
	(segment
		(start 27.328114 -289.966654)
		(end 28.433014 -289.966654)
		(width 0.381)
		(layer "F.Cu")
		(net "GND")
	)
	(segment
		(start 357.560626 -338.47024)
		(end 357.345234 -338.254848)
		(width 0.381)
		(layer "F.Cu")
		(net "GND")
	)
	(segment
		(start 216.38133 -41.341548)
		(end 216.38133 -40.706548)
		(width 0.3556)
		(layer "F.Cu")
		(net "GND")
	)
	(segment
		(start 27.328114 -216.866724)
		(end 28.433014 -216.866724)
		(width 0.381)
		(layer "F.Cu")
		(net "GND")
	)
	(segment
		(start 215.719914 -305.266598)
		(end 216.824814 -305.266598)
		(width 0.381)
		(layer "F.Cu")
		(net "GND")
	)
	(segment
		(start 170.457114 -215.166702)
		(end 171.562014 -215.166702)
		(width 0.381)
		(layer "F.Cu")
		(net "GND")
	)
	(segment
		(start 364.389162 -285.939484)
		(end 364.389162 -286.47517)
		(width 0.254)
		(layer "F.Cu")
		(net "GND")
	)
	(segment
		(start 210.94192 -134.065518)
		(end 211.059522 -134.18312)
		(width 0.254)
		(layer "F.Cu")
		(net "GND")
	)
	(segment
		(start 207.071214 -221.116652)
		(end 208.176114 -221.116652)
		(width 0.381)
		(layer "F.Cu")
		(net "GND")
	)
	(segment
		(start 166.357046 -278.066754)
		(end 167.461946 -278.066754)
		(width 0.381)
		(layer "F.Cu")
		(net "GND")
	)
	(segment
		(start 368.50828 -232.250234)
		(end 368.50828 -231.714548)
		(width 0.2032)
		(layer "F.Cu")
		(net "GND")
	)
	(segment
		(start 94.418404 -94.899988)
		(end 94.9452 -95.426784)
		(width 0.3556)
		(layer "F.Cu")
		(net "GND")
	)
	(segment
		(start 427.045882 -278.916638)
		(end 425.940982 -278.916638)
		(width 0.381)
		(layer "F.Cu")
		(net "GND")
	)
	(segment
		(start 337.604862 -267.219938)
		(end 337.604862 -267.755878)
		(width 0.2032)
		(layer "F.Cu")
		(net "GND")
	)
	(segment
		(start 128.666494 -264.778236)
		(end 128.666748 -265.314176)
		(width 0.2032)
		(layer "F.Cu")
		(net "GND")
	)
	(segment
		(start 312.987182 -233.86669)
		(end 314.092082 -233.86669)
		(width 0.381)
		(layer "F.Cu")
		(net "GND")
	)
	(segment
		(start 297.899582 -222.816674)
		(end 299.004482 -222.816674)
		(width 0.381)
		(layer "F.Cu")
		(net "GND")
	)
	(segment
		(start 179.105814 -198.166736)
		(end 178.000914 -198.166736)
		(width 0.381)
		(layer "F.Cu")
		(net "GND")
	)
	(segment
		(start 165.140894 -285.716726)
		(end 165.082728 -285.65856)
		(width 0.381)
		(layer "F.Cu")
		(net "GND")
	)
	(segment
		(start 200.632314 -266.1666)
		(end 201.737214 -266.1666)
		(width 0.381)
		(layer "F.Cu")
		(net "GND")
	)
	(segment
		(start 14.579346 -240.666778)
		(end 15.684246 -240.666778)
		(width 0.381)
		(layer "F.Cu")
		(net "GND")
	)
	(segment
		(start 173.900846 -317.166752)
		(end 175.005746 -317.166752)
		(width 0.381)
		(layer "F.Cu")
		(net "GND")
	)
	(segment
		(start 39.566088 -335.471262)
		(end 40.506396 -335.471262)
		(width 0.508)
		(layer "F.Cu")
		(net "GND")
	)
	(segment
		(start 166.357046 -225.36658)
		(end 165.252146 -225.36658)
		(width 0.381)
		(layer "F.Cu")
		(net "GND")
	)
	(segment
		(start 214.615014 -303.566576)
		(end 215.719914 -303.566576)
		(width 0.381)
		(layer "F.Cu")
		(net "GND")
	)
	(segment
		(start 458.24775 -382.90627)
		(end 458.32014 -382.83388)
		(width 0.1778)
		(layer "F.Cu")
		(net "GND")
	)
	(segment
		(start 164.018214 -297.616626)
		(end 162.913314 -297.616626)
		(width 0.381)
		(layer "F.Cu")
		(net "GND")
	)
	(segment
		(start 131.547108 -17.655032)
		(end 131.547108 -16.550132)
		(width 0.3556)
		(layer "F.Cu")
		(net "GND")
	)
	(segment
		(start 376.606562 -264.778236)
		(end 376.606816 -265.314176)
		(width 0.2032)
		(layer "F.Cu")
		(net "GND")
	)
	(segment
		(start 281.707082 -224.516696)
		(end 282.811982 -224.516696)
		(width 0.381)
		(layer "F.Cu")
		(net "GND")
	)
	(segment
		(start 267.724382 -299.316648)
		(end 268.829282 -299.316648)
		(width 0.381)
		(layer "F.Cu")
		(net "GND")
	)
	(segment
		(start 380.835916 -261.244588)
		(end 380.835662 -261.244842)
		(width 0.2032)
		(layer "F.Cu")
		(net "GND")
	)
	(segment
		(start 458.455014 -287.416748)
		(end 459.559914 -287.416748)
		(width 0.381)
		(layer "F.Cu")
		(net "GND")
	)
	(segment
		(start 432.379882 -222.816674)
		(end 433.484782 -222.816674)
		(width 0.381)
		(layer "F.Cu")
		(net "GND")
	)
	(segment
		(start 132.895848 -268.84757)
		(end 132.895848 -269.38351)
		(width 0.2032)
		(layer "F.Cu")
		(net "GND")
	)
	(segment
		(start 420.736014 -258.516628)
		(end 421.840914 -258.516628)
		(width 0.381)
		(layer "F.Cu")
		(net "GND")
	)
	(segment
		(start 102.712266 -232.250488)
		(end 102.712266 -231.714802)
		(width 0.254)
		(layer "F.Cu")
		(net "GND")
	)
	(segment
		(start 113.629694 -258.2672)
		(end 113.629694 -258.80314)
		(width 0.254)
		(layer "F.Cu")
		(net "GND")
	)
	(segment
		(start 304.338482 -239.81664)
		(end 305.443382 -239.81664)
		(width 0.381)
		(layer "F.Cu")
		(net "GND")
	)
	(segment
		(start 338.074762 -281.05608)
		(end 338.074762 -281.59202)
		(width 0.2032)
		(layer "F.Cu")
		(net "GND")
	)
	(segment
		(start 181.444646 -221.96679)
		(end 182.549546 -221.96679)
		(width 0.381)
		(layer "F.Cu")
		(net "GND")
	)
	(segment
		(start 132.785612 -242.016788)
		(end 132.785612 -241.481102)
		(width 0.2032)
		(layer "F.Cu")
		(net "GND")
	)
	(segment
		(start 382.135634 -223.297496)
		(end 382.135634 -222.761556)
		(width 0.254)
		(layer "F.Cu")
		(net "GND")
	)
	(segment
		(start 385.534662 -278.614378)
		(end 386.004562 -278.336502)
		(width 0.254)
		(layer "F.Cu")
		(net "GND")
	)
	(segment
		(start 200.632314 -299.316648)
		(end 201.737214 -299.316648)
		(width 0.381)
		(layer "F.Cu")
		(net "GND")
	)
	(segment
		(start 301.01032 -411.204156)
		(end 300.34738 -411.204156)
		(width 0.3556)
		(layer "F.Cu")
		(net "GND")
	)
	(segment
		(start 57.503314 -289.966654)
		(end 58.608214 -289.966654)
		(width 0.381)
		(layer "F.Cu")
		(net "GND")
	)
	(segment
		(start 347.36278 -236.319822)
		(end 347.363034 -236.319568)
		(width 0.2032)
		(layer "F.Cu")
		(net "GND")
	)
	(segment
		(start 89.554812 -245.272306)
		(end 89.554812 -244.73662)
		(width 0.2032)
		(layer "F.Cu")
		(net "GND")
	)
	(segment
		(start 213.6394 -121.1072)
		(end 213.249256 -121.1072)
		(width 0.3556)
		(layer "F.Cu")
		(net "GND")
	)
	(segment
		(start 277.607014 -208.366614)
		(end 278.711914 -208.366614)
		(width 0.381)
		(layer "F.Cu")
		(net "GND")
	)
	(segment
		(start 282.811982 -235.566712)
		(end 283.916882 -235.566712)
		(width 0.381)
		(layer "F.Cu")
		(net "GND")
	)
	(segment
		(start 335.899252 -59.636152)
		(end 335.899252 -59.265312)
		(width 0.2032)
		(layer "F.Cu")
		(net "GND")
	)
	(segment
		(start 185.544714 -230.466646)
		(end 186.649614 -230.466646)
		(width 0.381)
		(layer "F.Cu")
		(net "GND")
	)
	(segment
		(start 375.197116 -283.497782)
		(end 375.197116 -284.033468)
		(width 0.254)
		(layer "F.Cu")
		(net "GND")
	)
	(segment
		(start 108.351066 -220.855794)
		(end 108.351066 -220.319854)
		(width 0.2032)
		(layer "F.Cu")
		(net "GND")
	)
	(segment
		(start 45.859446 -268.71676)
		(end 46.964346 -268.71676)
		(width 0.381)
		(layer "F.Cu")
		(net "GND")
	)
	(segment
		(start 11.135614 -262.76681)
		(end 12.240514 -262.76681)
		(width 0.381)
		(layer "F.Cu")
		(net "GND")
	)
	(segment
		(start 48.854614 -277.216616)
		(end 49.959514 -277.216616)
		(width 0.381)
		(layer "F.Cu")
		(net "GND")
	)
	(segment
		(start 458.455014 -272.116804)
		(end 459.559914 -272.116804)
		(width 0.381)
		(layer "F.Cu")
		(net "GND")
	)
	(segment
		(start 178.000914 -221.116652)
		(end 176.896014 -221.116652)
		(width 0.381)
		(layer "F.Cu")
		(net "GND")
	)
	(segment
		(start 308.887114 -278.066754)
		(end 309.992014 -278.066754)
		(width 0.381)
		(layer "F.Cu")
		(net "GND")
	)
	(segment
		(start 7.035546 -229.616762)
		(end 8.140446 -229.616762)
		(width 0.381)
		(layer "F.Cu")
		(net "GND")
	)
	(segment
		(start 427.045882 -316.316614)
		(end 425.940982 -316.316614)
		(width 0.381)
		(layer "F.Cu")
		(net "GND")
	)
	(segment
		(start 333.944214 -17.437608)
		(end 333.944214 -16.847312)
		(width 0.381)
		(layer "F.Cu")
		(net "GND")
	)
	(segment
		(start 118.218966 -220.041724)
		(end 118.218966 -219.506038)
		(width 0.254)
		(layer "F.Cu")
		(net "GND")
	)
	(segment
		(start 425.940982 -207.51673)
		(end 427.045882 -207.51673)
		(width 0.381)
		(layer "F.Cu")
		(net "GND")
	)
	(segment
		(start 95.3897 -422.870376)
		(end 95.3897 -422.161208)
		(width 0.3556)
		(layer "F.Cu")
		(net "GND")
	)
	(segment
		(start 272.273014 -204.96657)
		(end 271.168114 -204.96657)
		(width 0.381)
		(layer "F.Cu")
		(net "GND")
	)
	(segment
		(start 120.678448 -280.77795)
		(end 120.678194 -280.778204)
		(width 0.254)
		(layer "F.Cu")
		(net "GND")
	)
	(segment
		(start 191.988186 -429.01108)
		(end 191.988186 -428.26686)
		(width 0.3556)
		(layer "F.Cu")
		(net "GND")
	)
	(segment
		(start 98.592894 -281.591766)
		(end 98.593148 -281.59202)
		(width 0.254)
		(layer "F.Cu")
		(net "GND")
	)
	(segment
		(start 267.724382 -284.866588)
		(end 268.829282 -284.866588)
		(width 0.381)
		(layer "F.Cu")
		(net "GND")
	)
	(segment
		(start 290.355782 -310.366664)
		(end 291.460682 -310.366664)
		(width 0.381)
		(layer "F.Cu")
		(net "GND")
	)
	(segment
		(start 185.544714 -297.616626)
		(end 186.649614 -297.616626)
		(width 0.381)
		(layer "F.Cu")
		(net "GND")
	)
	(segment
		(start 7.035546 -220.266768)
		(end 8.140446 -220.266768)
		(width 0.381)
		(layer "F.Cu")
		(net "GND")
	)
	(segment
		(start 94.833694 -282.683966)
		(end 94.833694 -283.219906)
		(width 0.2032)
		(layer "F.Cu")
		(net "GND")
	)
	(segment
		(start 98.482912 -242.830858)
		(end 98.482912 -242.295172)
		(width 0.2032)
		(layer "F.Cu")
		(net "GND")
	)
	(segment
		(start 12.240514 -205.816708)
		(end 13.345414 -205.816708)
		(width 0.381)
		(layer "F.Cu")
		(net "GND")
	)
	(segment
		(start 286.255714 -251.716794)
		(end 287.360614 -251.716794)
		(width 0.381)
		(layer "F.Cu")
		(net "GND")
	)
	(segment
		(start 292.556692 -344.700352)
		(end 293.497 -344.700352)
		(width 0.508)
		(layer "F.Cu")
		(net "GND")
	)
	(segment
		(start 349.24238 -234.69219)
		(end 349.24238 -234.15625)
		(width 0.2032)
		(layer "F.Cu")
		(net "GND")
	)
	(segment
		(start 405.648414 -242.3668)
		(end 406.753314 -242.3668)
		(width 0.381)
		(layer "F.Cu")
		(net "GND")
	)
	(segment
		(start 348.772734 -242.017042)
		(end 348.772734 -241.481102)
		(width 0.254)
		(layer "F.Cu")
		(net "GND")
	)
	(segment
		(start 445.577214 -298.466764)
		(end 444.472314 -298.466764)
		(width 0.381)
		(layer "F.Cu")
		(net "GND")
	)
	(segment
		(start 444.472314 -233.016806)
		(end 445.577214 -233.016806)
		(width 0.381)
		(layer "F.Cu")
		(net "GND")
	)
	(segment
		(start 368.97818 -226.017582)
		(end 368.978434 -226.017328)
		(width 0.254)
		(layer "F.Cu")
		(net "GND")
	)
	(segment
		(start 281.707082 -258.516628)
		(end 282.811982 -258.516628)
		(width 0.381)
		(layer "F.Cu")
		(net "GND")
	)
	(segment
		(start 210.514946 -212.616796)
		(end 211.619846 -212.616796)
		(width 0.381)
		(layer "F.Cu")
		(net "GND")
	)
	(segment
		(start 405.634952 -203.266802)
		(end 406.753314 -203.266802)
		(width 0.381)
		(layer "F.Cu")
		(net "GND")
	)
	(segment
		(start 215.922352 -25.311354)
		(end 217.062558 -25.311354)
		(width 0.3556)
		(layer "F.Cu")
		(net "GND")
	)
	(segment
		(start 40.27678 -386.95122)
		(end 40.27678 -386.329174)
		(width 0.4572)
		(layer "F.Cu")
		(net "GND")
	)
	(segment
		(start 98.953066 -217.600276)
		(end 98.953066 -217.064336)
		(width 0.2032)
		(layer "F.Cu")
		(net "GND")
	)
	(segment
		(start 94.723712 -222.76181)
		(end 94.723966 -222.761556)
		(width 0.254)
		(layer "F.Cu")
		(net "GND")
	)
	(segment
		(start 258.34467 -52.507642)
		(end 257.27533 -52.507642)
		(width 0.254)
		(layer "F.Cu")
		(net "GND")
	)
	(segment
		(start 413.192214 -298.466764)
		(end 414.297114 -298.466764)
		(width 0.381)
		(layer "F.Cu")
		(net "GND")
	)
	(segment
		(start 413.192214 -214.316564)
		(end 414.297114 -214.316564)
		(width 0.381)
		(layer "F.Cu")
		(net "GND")
	)
	(segment
		(start 333.944214 -17.70507)
		(end 333.944214 -17.437608)
		(width 0.3556)
		(layer "F.Cu")
		(net "GND")
	)
	(segment
		(start 436.928514 -248.31675)
		(end 438.033414 -248.31675)
		(width 0.381)
		(layer "F.Cu")
		(net "GND")
	)
	(segment
		(start 250.490228 -92.36964)
		(end 250.490228 -91.709748)
		(width 0.3556)
		(layer "F.Cu")
		(net "GND")
	)
	(segment
		(start 310.82488 -55.336948)
		(end 309.71617 -56.445658)
		(width 0.3556)
		(layer "F.Cu")
		(net "GND")
	)
	(segment
		(start 23.228046 -199.01662)
		(end 24.332946 -199.01662)
		(width 0.381)
		(layer "F.Cu")
		(net "GND")
	)
	(segment
		(start 136.075166 -221.133924)
		(end 136.075166 -221.669864)
		(width 0.2032)
		(layer "F.Cu")
		(net "GND")
	)
	(segment
		(start 52.72913 -144.744186)
		(end 53.07457 -145.089626)
		(width 0.2032)
		(layer "F.Cu")
		(net "GND")
	)
	(segment
		(start 124.437648 -283.497782)
		(end 124.437648 -284.033468)
		(width 0.254)
		(layer "F.Cu")
		(net "GND")
	)
	(segment
		(start 23.228046 -287.416748)
		(end 22.123146 -287.416748)
		(width 0.381)
		(layer "F.Cu")
		(net "GND")
	)
	(segment
		(start 100.942648 -278.614378)
		(end 100.942648 -279.150318)
		(width 0.2032)
		(layer "F.Cu")
		(net "GND")
	)
	(segment
		(start 185.544714 -239.81664)
		(end 186.649614 -239.81664)
		(width 0.381)
		(layer "F.Cu")
		(net "GND")
	)
	(segment
		(start 159.274256 -65.094358)
		(end 159.909256 -65.094358)
		(width 0.3556)
		(layer "F.Cu")
		(net "GND")
	)
	(segment
		(start 458.455014 -220.266768)
		(end 459.559914 -220.266768)
		(width 0.381)
		(layer "F.Cu")
		(net "GND")
	)
	(segment
		(start 58.824114 -210.066636)
		(end 57.503314 -210.066636)
		(width 0.381)
		(layer "F.Cu")
		(net "GND")
	)
	(segment
		(start 378.846334 -214.344758)
		(end 378.846334 -213.732618)
		(width 0.254)
		(layer "F.Cu")
		(net "GND")
	)
	(segment
		(start 165.252146 -315.46673)
		(end 166.357046 -315.46673)
		(width 0.381)
		(layer "F.Cu")
		(net "GND")
	)
	(segment
		(start 343.60358 -216.250774)
		(end 343.603834 -216.25052)
		(width 0.254)
		(layer "F.Cu")
		(net "GND")
	)
	(segment
		(start 444.472314 -273.816572)
		(end 445.577214 -273.816572)
		(width 0.381)
		(layer "F.Cu")
		(net "GND")
	)
	(segment
		(start 296.794682 -277.216616)
		(end 297.899582 -277.216616)
		(width 0.381)
		(layer "F.Cu")
		(net "GND")
	)
	(segment
		(start 266.619482 -297.616626)
		(end 267.724382 -297.616626)
		(width 0.381)
		(layer "F.Cu")
		(net "GND")
	)
	(segment
		(start 342.912192 -42.649648)
		(end 343.005156 -42.811446)
		(width 0.2032)
		(layer "F.Cu")
		(net "GND")
	)
	(segment
		(start 212.724746 -292.516814)
		(end 211.619846 -292.516814)
		(width 0.381)
		(layer "F.Cu")
		(net "GND")
	)
	(segment
		(start 386.83438 -221.669864)
		(end 386.834634 -221.133924)
		(width 0.254)
		(layer "F.Cu")
		(net "GND")
	)
	(segment
		(start 98.592894 -279.428194)
		(end 98.592894 -279.96388)
		(width 0.254)
		(layer "F.Cu")
		(net "GND")
	)
	(segment
		(start 443.860428 -30.827218)
		(end 443.853316 -30.820106)
		(width 0.17272)
		(layer "F.Cu")
		(net "GND")
	)
	(segment
		(start 355.461316 -285.125414)
		(end 355.461316 -285.6611)
		(width 0.254)
		(layer "F.Cu")
		(net "GND")
	)
	(segment
		(start 129.496312 -226.553268)
		(end 129.496312 -226.017582)
		(width 0.254)
		(layer "F.Cu")
		(net "GND")
	)
	(segment
		(start 409.748482 -213.46668)
		(end 410.853382 -213.46668)
		(width 0.381)
		(layer "F.Cu")
		(net "GND")
	)
	(segment
		(start 365.83493 -355.651816)
		(end 366.229138 -355.651816)
		(width 0.381)
		(layer "F.Cu")
		(net "GND")
	)
	(segment
		(start 89.555066 -232.250488)
		(end 89.554812 -232.250234)
		(width 0.2032)
		(layer "F.Cu")
		(net "GND")
	)
	(segment
		(start 136.545066 -217.600276)
		(end 136.545066 -217.064336)
		(width 0.20066)
		(layer "F.Cu")
		(net "GND")
	)
	(segment
		(start 169.352214 -205.816708)
		(end 170.457114 -205.816708)
		(width 0.381)
		(layer "F.Cu")
		(net "GND")
	)
	(segment
		(start 172.795946 -236.416596)
		(end 173.900846 -236.416596)
		(width 0.381)
		(layer "F.Cu")
		(net "GND")
	)
	(segment
		(start 445.577214 -212.616796)
		(end 444.472314 -212.616796)
		(width 0.381)
		(layer "F.Cu")
		(net "GND")
	)
	(segment
		(start 380.365762 -279.428194)
		(end 380.365762 -279.964134)
		(width 0.254)
		(layer "F.Cu")
		(net "GND")
	)
	(segment
		(start 32.58185 -169.04081)
		(end 31.940246 -169.04081)
		(width 0.381)
		(layer "F.Cu")
		(net "GND")
	)
	(segment
		(start 275.268182 -306.96662)
		(end 274.163282 -306.96662)
		(width 0.381)
		(layer "F.Cu")
		(net "GND")
	)
	(segment
		(start 178.1556 -111.375444)
		(end 177.75555 -110.975394)
		(width 0.3556)
		(layer "F.Cu")
		(net "GND")
	)
	(segment
		(start 89.084912 -222.76181)
		(end 89.085166 -222.761556)
		(width 0.254)
		(layer "F.Cu")
		(net "GND")
	)
	(segment
		(start 462.555082 -233.86669)
		(end 463.659982 -233.86669)
		(width 0.381)
		(layer "F.Cu")
		(net "GND")
	)
	(segment
		(start 444.472314 -290.816792)
		(end 445.577214 -290.816792)
		(width 0.381)
		(layer "F.Cu")
		(net "GND")
	)
	(segment
		(start 175.005746 -272.116804)
		(end 173.900846 -272.116804)
		(width 0.381)
		(layer "F.Cu")
		(net "GND")
	)
	(segment
		(start 256.080514 -304.416714)
		(end 257.185414 -304.416714)
		(width 0.381)
		(layer "F.Cu")
		(net "GND")
	)
	(segment
		(start 115.979448 -265.592306)
		(end 115.979448 -266.127992)
		(width 0.254)
		(layer "F.Cu")
		(net "GND")
	)
	(segment
		(start 378.016516 -267.219938)
		(end 378.016516 -267.755624)
		(width 0.254)
		(layer "F.Cu")
		(net "GND")
	)
	(segment
		(start 133.835648 -257.45313)
		(end 133.835648 -257.98907)
		(width 0.2032)
		(layer "F.Cu")
		(net "GND")
	)
	(segment
		(start 405.648414 -223.666558)
		(end 406.753314 -223.666558)
		(width 0.381)
		(layer "F.Cu")
		(net "GND")
	)
	(segment
		(start 352.06178 -220.041978)
		(end 352.062034 -220.041724)
		(width 0.254)
		(layer "F.Cu")
		(net "GND")
	)
	(segment
		(start 110.230666 -239.853724)
		(end 110.23092 -239.85347)
		(width 0.254)
		(layer "F.Cu")
		(net "GND")
	)
	(segment
		(start 7.035546 -261.916672)
		(end 8.140446 -261.916672)
		(width 0.381)
		(layer "F.Cu")
		(net "GND")
	)
	(segment
		(start 211.619846 -311.216802)
		(end 210.514946 -311.216802)
		(width 0.381)
		(layer "F.Cu")
		(net "GND")
	)
	(segment
		(start 412.172404 -288.317432)
		(end 411.958282 -288.317432)
		(width 0.381)
		(layer "F.Cu")
		(net "GND")
	)
	(segment
		(start 354.991162 -269.66164)
		(end 354.991162 -270.197326)
		(width 0.2032)
		(layer "F.Cu")
		(net "GND")
	)
	(segment
		(start 130.906266 -240.389156)
		(end 130.906012 -240.388902)
		(width 0.2032)
		(layer "F.Cu")
		(net "GND")
	)
	(segment
		(start 383.07518 -224.925382)
		(end 383.07518 -224.389442)
		(width 0.254)
		(layer "F.Cu")
		(net "GND")
	)
	(segment
		(start 449.677282 -312.91657)
		(end 448.572382 -312.91657)
		(width 0.381)
		(layer "F.Cu")
		(net "GND")
	)
	(segment
		(start 190.093346 -203.266802)
		(end 188.988446 -203.266802)
		(width 0.381)
		(layer "F.Cu")
		(net "GND")
	)
	(segment
		(start 17.658842 -106.910124)
		(end 17.445482 -107.123484)
		(width 0.3556)
		(layer "F.Cu")
		(net "GND")
	)
	(segment
		(start 307.782214 -229.616762)
		(end 308.887114 -229.616762)
		(width 0.381)
		(layer "F.Cu")
		(net "GND")
	)
	(segment
		(start 242.12169 -248.2215)
		(end 242.12169 -247.051068)
		(width 0.3556)
		(layer "F.Cu")
		(net "GND")
	)
	(segment
		(start 425.940982 -239.81664)
		(end 424.836082 -239.81664)
		(width 0.381)
		(layer "F.Cu")
		(net "GND")
	)
	(segment
		(start 120.733312 -16.91005)
		(end 121.47296 -16.91005)
		(width 0.3556)
		(layer "F.Cu")
		(net "GND")
	)
	(segment
		(start 328.625708 -41.401746)
		(end 328.244962 -41.947084)
		(width 0.2032)
		(layer "F.Cu")
		(net "GND")
	)
	(segment
		(start 15.684246 -217.716608)
		(end 16.789146 -217.716608)
		(width 0.381)
		(layer "F.Cu")
		(net "GND")
	)
	(segment
		(start 45.859446 -203.266802)
		(end 46.964346 -203.266802)
		(width 0.381)
		(layer "F.Cu")
		(net "GND")
	)
	(segment
		(start 23.228046 -263.616694)
		(end 24.332946 -263.616694)
		(width 0.381)
		(layer "F.Cu")
		(net "GND")
	)
	(segment
		(start 448.572382 -216.866724)
		(end 447.467482 -216.866724)
		(width 0.381)
		(layer "F.Cu")
		(net "GND")
	)
	(segment
		(start 370.858034 -231.436164)
		(end 370.858034 -230.900478)
		(width 0.254)
		(layer "F.Cu")
		(net "GND")
	)
	(segment
		(start 345.15171 -54.354476)
		(end 345.416124 -54.747668)
		(width 0.1778)
		(layer "F.Cu")
		(net "GND")
	)
	(segment
		(start 278.711914 -240.666778)
		(end 279.816814 -240.666778)
		(width 0.381)
		(layer "F.Cu")
		(net "GND")
	)
	(segment
		(start 439.923682 -226.216718)
		(end 441.028582 -226.216718)
		(width 0.381)
		(layer "F.Cu")
		(net "GND")
	)
	(segment
		(start 418.397182 -196.466714)
		(end 417.292282 -196.466714)
		(width 0.381)
		(layer "F.Cu")
		(net "GND")
	)
	(segment
		(start 215.719914 -235.566712)
		(end 216.824814 -235.566712)
		(width 0.381)
		(layer "F.Cu")
		(net "GND")
	)
	(segment
		(start 453.121014 -273.816572)
		(end 452.016114 -273.816572)
		(width 0.381)
		(layer "F.Cu")
		(net "GND")
	)
	(segment
		(start 44.754546 -272.116804)
		(end 45.859446 -272.116804)
		(width 0.381)
		(layer "F.Cu")
		(net "GND")
	)
	(segment
		(start 410.853382 -216.866724)
		(end 412.232094 -216.866724)
		(width 0.381)
		(layer "F.Cu")
		(net "GND")
	)
	(segment
		(start 377.076716 -259.093462)
		(end 377.076462 -259.616956)
		(width 0.2032)
		(layer "F.Cu")
		(net "GND")
	)
	(segment
		(start 345.953334 -233.87812)
		(end 345.953334 -233.34218)
		(width 0.2032)
		(layer "F.Cu")
		(net "GND")
	)
	(segment
		(start 340.562946 -54.558946)
		(end 340.87689 -53.983636)
		(width 0.2032)
		(layer "F.Cu")
		(net "GND")
	)
	(segment
		(start 105.641394 -277.522178)
		(end 105.641394 -277.522432)
		(width 0.2032)
		(layer "F.Cu")
		(net "GND")
	)
	(segment
		(start 370.85778 -222.76181)
		(end 370.858034 -222.761556)
		(width 0.254)
		(layer "F.Cu")
		(net "GND")
	)
	(segment
		(start 59.842146 -225.36658)
		(end 60.947046 -225.36658)
		(width 0.381)
		(layer "F.Cu")
		(net "GND")
	)
	(segment
		(start 26.223214 -221.116652)
		(end 27.328114 -221.116652)
		(width 0.381)
		(layer "F.Cu")
		(net "GND")
	)
	(segment
		(start 202.971146 -199.01662)
		(end 204.076046 -199.01662)
		(width 0.381)
		(layer "F.Cu")
		(net "GND")
	)
	(segment
		(start 368.618516 -281.869896)
		(end 368.618516 -282.405582)
		(width 0.254)
		(layer "F.Cu")
		(net "GND")
	)
	(segment
		(start 289.250882 -286.56661)
		(end 290.355782 -286.56661)
		(width 0.381)
		(layer "F.Cu")
		(net "GND")
	)
	(segment
		(start 459.559914 -204.96657)
		(end 458.455014 -204.96657)
		(width 0.381)
		(layer "F.Cu")
		(net "GND")
	)
	(segment
		(start 422.945814 -301.866808)
		(end 421.840914 -301.866808)
		(width 0.381)
		(layer "F.Cu")
		(net "GND")
	)
	(segment
		(start 293.799514 -248.31675)
		(end 294.904414 -248.31675)
		(width 0.381)
		(layer "F.Cu")
		(net "GND")
	)
	(segment
		(start 75.016868 -17.148302)
		(end 74.407268 -17.148302)
		(width 0.4572)
		(layer "F.Cu")
		(net "GND")
	)
	(segment
		(start 363.809534 -227.367084)
		(end 363.809534 -226.831144)
		(width 0.2032)
		(layer "F.Cu")
		(net "GND")
	)
	(segment
		(start 263.624314 -270.416782)
		(end 264.729214 -270.416782)
		(width 0.381)
		(layer "F.Cu")
		(net "GND")
	)
	(segment
		(start 56.398414 -216.866724)
		(end 57.503314 -216.866724)
		(width 0.381)
		(layer "F.Cu")
		(net "GND")
	)
	(segment
		(start 39.420546 -227.066602)
		(end 38.315646 -227.066602)
		(width 0.381)
		(layer "F.Cu")
		(net "GND")
	)
	(segment
		(start 341.364316 -283.497782)
		(end 341.364316 -284.033468)
		(width 0.254)
		(layer "F.Cu")
		(net "GND")
	)
	(segment
		(start 290.355782 -245.76659)
		(end 291.460682 -245.76659)
		(width 0.381)
		(layer "F.Cu")
		(net "GND")
	)
	(segment
		(start 288.545016 -367.792508)
		(end 288.418016 -367.919508)
		(width 0.381)
		(layer "F.Cu")
		(net "GND")
	)
	(segment
		(start 98.123248 -263.96442)
		(end 98.123248 -264.50036)
		(width 0.2032)
		(layer "F.Cu")
		(net "GND")
	)
	(segment
		(start 8.140446 -285.716726)
		(end 9.245346 -285.716726)
		(width 0.381)
		(layer "F.Cu")
		(net "GND")
	)
	(segment
		(start 47.62246 -144.463008)
		(end 47.78629 -144.626838)
		(width 0.3556)
		(layer "F.Cu")
		(net "GND")
	)
	(segment
		(start 290.355782 -215.166702)
		(end 291.460682 -215.166702)
		(width 0.381)
		(layer "F.Cu")
		(net "GND")
	)
	(segment
		(start 345.554554 -53.952902)
		(end 345.15171 -54.354476)
		(width 0.1778)
		(layer "F.Cu")
		(net "GND")
	)
	(segment
		(start 340.894162 -253.919482)
		(end 340.894416 -253.919736)
		(width 0.2032)
		(layer "F.Cu")
		(net "GND")
	)
	(segment
		(start 85.795866 -250.155964)
		(end 85.523324 -250.428506)
		(width 0.2032)
		(layer "F.Cu")
		(net "GND")
	)
	(segment
		(start 453.121014 -270.416782)
		(end 452.016114 -270.416782)
		(width 0.381)
		(layer "F.Cu")
		(net "GND")
	)
	(segment
		(start 382.135634 -245.55069)
		(end 382.135634 -246.08663)
		(width 0.2032)
		(layer "F.Cu")
		(net "GND")
	)
	(segment
		(start 409.748482 -301.01667)
		(end 410.853382 -301.01667)
		(width 0.381)
		(layer "F.Cu")
		(net "GND")
	)
	(segment
		(start 127.69596 -98.61042)
		(end 130.055112 -98.61042)
		(width 0.254)
		(layer "F.Cu")
		(net "GND")
	)
	(segment
		(start 441.028582 -230.466646)
		(end 442.133482 -230.466646)
		(width 0.381)
		(layer "F.Cu")
		(net "GND")
	)
	(segment
		(start 131.956048 -276.986492)
		(end 131.955794 -277.522432)
		(width 0.2032)
		(layer "F.Cu")
		(net "GND")
	)
	(segment
		(start 158.813246 -214.316564)
		(end 157.708346 -214.316564)
		(width 0.381)
		(layer "F.Cu")
		(net "GND")
	)
	(segment
		(start 300.238414 -300.166786)
		(end 301.343314 -300.166786)
		(width 0.381)
		(layer "F.Cu")
		(net "GND")
	)
	(segment
		(start 329.437492 -53.148738)
		(end 329.437746 -53.149246)
		(width 0.2032)
		(layer "F.Cu")
		(net "GND")
	)
	(segment
		(start 196.532246 -246.616728)
		(end 197.637146 -246.616728)
		(width 0.381)
		(layer "F.Cu")
		(net "GND")
	)
	(segment
		(start 333.26578 -223.297496)
		(end 333.26578 -222.761556)
		(width 0.254)
		(layer "F.Cu")
		(net "GND")
	)
	(segment
		(start 286.255714 -279.766776)
		(end 287.360614 -279.766776)
		(width 0.381)
		(layer "F.Cu")
		(net "GND")
	)
	(segment
		(start 343.550494 -49.389792)
		(end 343.822274 -49.859692)
		(width 0.254)
		(layer "F.Cu")
		(net "GND")
	)
	(segment
		(start 116.919248 -263.96442)
		(end 116.919248 -264.499852)
		(width 0.2032)
		(layer "F.Cu")
		(net "GND")
	)
	(segment
		(start 132.425694 -258.802886)
		(end 132.425948 -258.80314)
		(width 0.2032)
		(layer "F.Cu")
		(net "GND")
	)
	(segment
		(start 106.941112 -226.017582)
		(end 106.941366 -226.017328)
		(width 0.254)
		(layer "F.Cu")
		(net "GND")
	)
	(segment
		(start 91.904312 -226.553268)
		(end 91.904312 -226.017582)
		(width 0.254)
		(layer "F.Cu")
		(net "GND")
	)
	(segment
		(start 338.434934 -240.389156)
		(end 338.434934 -239.853216)
		(width 0.2032)
		(layer "F.Cu")
		(net "GND")
	)
	(segment
		(start 363.919516 -278.614378)
		(end 363.919516 -279.150064)
		(width 0.254)
		(layer "F.Cu")
		(net "GND")
	)
	(segment
		(start 135.245094 -281.05608)
		(end 135.245094 -281.59202)
		(width 0.254)
		(layer "F.Cu")
		(net "GND")
	)
	(segment
		(start 207.071214 -202.416664)
		(end 208.176114 -202.416664)
		(width 0.381)
		(layer "F.Cu")
		(net "GND")
	)
	(segment
		(start 35.976814 -288.266632)
		(end 34.871914 -288.266632)
		(width 0.381)
		(layer "F.Cu")
		(net "GND")
	)
	(segment
		(start 136.184894 -271.289272)
		(end 136.654794 -271.011396)
		(width 0.254)
		(layer "F.Cu")
		(net "GND")
	)
	(segment
		(start 362.69676 -401.787614)
		(end 362.69676 -402.672042)
		(width 0.3556)
		(layer "F.Cu")
		(net "GND")
	)
	(segment
		(start 135.135112 -226.553268)
		(end 135.135112 -226.017582)
		(width 0.254)
		(layer "F.Cu")
		(net "GND")
	)
	(segment
		(start 345.593162 -278.336248)
		(end 345.593416 -278.336502)
		(width 0.254)
		(layer "F.Cu")
		(net "GND")
	)
	(segment
		(start 92.954094 -285.939484)
		(end 92.954094 -286.47517)
		(width 0.2032)
		(layer "F.Cu")
		(net "GND")
	)
	(segment
		(start 120.678448 -264.499852)
		(end 120.678194 -264.500106)
		(width 0.2032)
		(layer "F.Cu")
		(net "GND")
	)
	(segment
		(start 87.205312 -242.830858)
		(end 87.205312 -242.294918)
		(width 0.254)
		(layer "F.Cu")
		(net "GND")
	)
	(segment
		(start 135.135112 -237.947454)
		(end 135.135112 -237.411768)
		(width 0.254)
		(layer "F.Cu")
		(net "GND")
	)
	(segment
		(start 452.016114 -220.266768)
		(end 450.911214 -220.266768)
		(width 0.381)
		(layer "F.Cu")
		(net "GND")
	)
	(segment
		(start 180.339746 -204.96657)
		(end 181.444646 -204.96657)
		(width 0.381)
		(layer "F.Cu")
		(net "GND")
	)
	(segment
		(start 344.073734 -237.133892)
		(end 344.07348 -237.133638)
		(width 0.2032)
		(layer "F.Cu")
		(net "GND")
	)
	(segment
		(start 410.853382 -226.216718)
		(end 409.748482 -226.216718)
		(width 0.381)
		(layer "F.Cu")
		(net "GND")
	)
	(segment
		(start 49.959514 -261.066788)
		(end 51.064414 -261.066788)
		(width 0.381)
		(layer "F.Cu")
		(net "GND")
	)
	(segment
		(start 312.987182 -314.616592)
		(end 314.092082 -314.616592)
		(width 0.381)
		(layer "F.Cu")
		(net "GND")
	)
	(segment
		(start 49.959514 -241.516662)
		(end 51.064414 -241.516662)
		(width 0.381)
		(layer "F.Cu")
		(net "GND")
	)
	(segment
		(start 364.92688 -393.598908)
		(end 364.92688 -393.240768)
		(width 0.3556)
		(layer "F.Cu")
		(net "GND")
	)
	(segment
		(start 59.842146 -229.616762)
		(end 60.947046 -229.616762)
		(width 0.381)
		(layer "F.Cu")
		(net "GND")
	)
	(segment
		(start 161.605214 -275.516594)
		(end 162.913314 -275.516594)
		(width 0.381)
		(layer "F.Cu")
		(net "GND")
	)
	(segment
		(start 7.899146 -100.287836)
		(end 7.899146 -100.19665)
		(width 0.3556)
		(layer "F.Cu")
		(net "GND")
	)
	(segment
		(start 286.255714 -216.016586)
		(end 287.360614 -216.016586)
		(width 0.381)
		(layer "F.Cu")
		(net "GND")
	)
	(segment
		(start 45.859446 -287.416748)
		(end 44.754546 -287.416748)
		(width 0.381)
		(layer "F.Cu")
		(net "GND")
	)
	(segment
		(start 14.265402 -106.32567)
		(end 14.445996 -106.506264)
		(width 0.3556)
		(layer "F.Cu")
		(net "GND")
	)
	(segment
		(start 12.240514 -275.516594)
		(end 13.345414 -275.516594)
		(width 0.381)
		(layer "F.Cu")
		(net "GND")
	)
	(segment
		(start 8.140446 -311.216802)
		(end 9.245346 -311.216802)
		(width 0.381)
		(layer "F.Cu")
		(net "GND")
	)
	(segment
		(start 425.44492 -367.0681)
		(end 425.281344 -367.231676)
		(width 0.381)
		(layer "F.Cu")
		(net "GND")
	)
	(segment
		(start 113.629694 -281.05608)
		(end 113.629694 -281.59202)
		(width 0.254)
		(layer "F.Cu")
		(net "GND")
	)
	(segment
		(start 125.267466 -214.344758)
		(end 125.267466 -213.732618)
		(width 0.254)
		(layer "F.Cu")
		(net "GND")
	)
	(segment
		(start 44.754546 -220.266768)
		(end 45.859446 -220.266768)
		(width 0.381)
		(layer "F.Cu")
		(net "GND")
	)
	(segment
		(start 425.96689 -11.26998)
		(end 425.96689 -12.37488)
		(width 0.3556)
		(layer "F.Cu")
		(net "GND")
	)
	(segment
		(start 417.292282 -299.316648)
		(end 418.397182 -299.316648)
		(width 0.381)
		(layer "F.Cu")
		(net "GND")
	)
	(segment
		(start 39.420546 -206.666592)
		(end 38.315646 -206.666592)
		(width 0.381)
		(layer "F.Cu")
		(net "GND")
	)
	(segment
		(start 130.906012 -243.644674)
		(end 130.906012 -243.108988)
		(width 0.2032)
		(layer "F.Cu")
		(net "GND")
	)
	(segment
		(start 185.544714 -282.316682)
		(end 186.649614 -282.316682)
		(width 0.381)
		(layer "F.Cu")
		(net "GND")
	)
	(segment
		(start 194.193414 -244.066568)
		(end 193.088514 -244.066568)
		(width 0.381)
		(layer "F.Cu")
		(net "GND")
	)
	(segment
		(start 9.277096 -101.095302)
		(end 7.525512 -101.095302)
		(width 0.3556)
		(layer "F.Cu")
		(net "GND")
	)
	(segment
		(start 8.140446 -197.316598)
		(end 9.245346 -197.316598)
		(width 0.381)
		(layer "F.Cu")
		(net "GND")
	)
	(segment
		(start 30.771846 -201.56678)
		(end 31.876746 -201.56678)
		(width 0.381)
		(layer "F.Cu")
		(net "GND")
	)
	(segment
		(start 342.194134 -248.528078)
		(end 342.19388 -248.527824)
		(width 0.2032)
		(layer "F.Cu")
		(net "GND")
	)
	(segment
		(start 256.080514 -231.316784)
		(end 257.185414 -231.316784)
		(width 0.381)
		(layer "F.Cu")
		(net "GND")
	)
	(segment
		(start 427.045882 -288.266632)
		(end 425.940982 -288.266632)
		(width 0.381)
		(layer "F.Cu")
		(net "GND")
	)
	(segment
		(start 204.076046 -210.916774)
		(end 205.180946 -210.916774)
		(width 0.381)
		(layer "F.Cu")
		(net "GND")
	)
	(segment
		(start 373.787162 -276.172676)
		(end 373.787162 -276.708616)
		(width 0.2032)
		(layer "F.Cu")
		(net "GND")
	)
	(segment
		(start 305.443382 -232.166668)
		(end 306.548282 -232.166668)
		(width 0.381)
		(layer "F.Cu")
		(net "GND")
	)
	(segment
		(start 275.268182 -245.76659)
		(end 274.163282 -245.76659)
		(width 0.381)
		(layer "F.Cu")
		(net "GND")
	)
	(segment
		(start 271.168114 -272.116804)
		(end 270.063214 -272.116804)
		(width 0.381)
		(layer "F.Cu")
		(net "GND")
	)
	(segment
		(start 193.78041 -118.074948)
		(end 194.39001 -118.074948)
		(width 0.3556)
		(layer "F.Cu")
		(net "GND")
	)
	(segment
		(start 19.784314 -266.1666)
		(end 20.889214 -266.1666)
		(width 0.381)
		(layer "F.Cu")
		(net "GND")
	)
	(segment
		(start 88.145366 -216.251028)
		(end 88.144858 -216.25052)
		(width 0.2032)
		(layer "F.Cu")
		(net "GND")
	)
	(segment
		(start 335.255362 -282.683966)
		(end 335.255362 -283.219906)
		(width 0.2032)
		(layer "F.Cu")
		(net "GND")
	)
	(segment
		(start 106.111294 -279.96388)
		(end 106.111548 -279.964134)
		(width 0.254)
		(layer "F.Cu")
		(net "GND")
	)
	(segment
		(start 88.615012 -240.388902)
		(end 88.615012 -239.853216)
		(width 0.2032)
		(layer "F.Cu")
		(net "GND")
	)
	(segment
		(start 402.046948 -11.26998)
		(end 402.046948 -10.16508)
		(width 0.3556)
		(layer "F.Cu")
		(net "GND")
	)
	(segment
		(start 159.918146 -265.316716)
		(end 158.813246 -265.316716)
		(width 0.381)
		(layer "F.Cu")
		(net "GND")
	)
	(segment
		(start 448.71259 -41.747948)
		(end 449.194682 -42.23004)
		(width 0.3556)
		(layer "F.Cu")
		(net "GND")
	)
	(segment
		(start 125.737366 -244.45849)
		(end 125.737366 -243.922804)
		(width 0.2032)
		(layer "F.Cu")
		(net "GND")
	)
	(segment
		(start 200.632314 -297.616626)
		(end 201.737214 -297.616626)
		(width 0.381)
		(layer "F.Cu")
		(net "GND")
	)
	(segment
		(start 22.123146 -203.266802)
		(end 23.228046 -203.266802)
		(width 0.381)
		(layer "F.Cu")
		(net "GND")
	)
	(segment
		(start 43.520614 -264.466578)
		(end 42.415714 -264.466578)
		(width 0.381)
		(layer "F.Cu")
		(net "GND")
	)
	(segment
		(start 11.135614 -250.866656)
		(end 12.240514 -250.866656)
		(width 0.381)
		(layer "F.Cu")
		(net "GND")
	)
	(segment
		(start 179.105814 -250.866656)
		(end 178.000914 -250.866656)
		(width 0.381)
		(layer "F.Cu")
		(net "GND")
	)
	(segment
		(start 44.754546 -227.066602)
		(end 45.859446 -227.066602)
		(width 0.381)
		(layer "F.Cu")
		(net "GND")
	)
	(segment
		(start 52.500276 -153.380186)
		(end 52.023264 -152.903174)
		(width 0.2032)
		(layer "F.Cu")
		(net "GND")
	)
	(segment
		(start 43.520614 -275.516594)
		(end 42.415714 -275.516594)
		(width 0.381)
		(layer "F.Cu")
		(net "GND")
	)
	(segment
		(start 312.987182 -288.266632)
		(end 314.092082 -288.266632)
		(width 0.381)
		(layer "F.Cu")
		(net "GND")
	)
	(segment
		(start 339.374734 -237.133892)
		(end 339.37448 -237.133638)
		(width 0.2032)
		(layer "F.Cu")
		(net "GND")
	)
	(segment
		(start 7.035546 -287.416748)
		(end 8.140446 -287.416748)
		(width 0.381)
		(layer "F.Cu")
		(net "GND")
	)
	(segment
		(start 94.253812 -243.644674)
		(end 94.253812 -243.108988)
		(width 0.2032)
		(layer "F.Cu")
		(net "GND")
	)
	(segment
		(start 385.97205 -29.181298)
		(end 386.443728 -28.70962)
		(width 0.3556)
		(layer "F.Cu")
		(net "GND")
	)
	(segment
		(start 11.135614 -312.91657)
		(end 12.240514 -312.91657)
		(width 0.381)
		(layer "F.Cu")
		(net "GND")
	)
	(segment
		(start 372.377716 -267.219938)
		(end 372.377462 -267.755878)
		(width 0.2032)
		(layer "F.Cu")
		(net "GND")
	)
	(segment
		(start 381.305562 -264.778236)
		(end 381.305562 -265.314176)
		(width 0.2032)
		(layer "F.Cu")
		(net "GND")
	)
	(segment
		(start 194.193414 -250.866656)
		(end 193.088514 -250.866656)
		(width 0.381)
		(layer "F.Cu")
		(net "GND")
	)
	(segment
		(start 151.96693 -44.351448)
		(end 151.96693 -43.652948)
		(width 0.3556)
		(layer "F.Cu")
		(net "GND")
	)
	(segment
		(start 381.19558 -237.947454)
		(end 381.19558 -237.411514)
		(width 0.254)
		(layer "F.Cu")
		(net "GND")
	)
	(segment
		(start 463.963004 -93.396054)
		(end 464.572604 -93.396054)
		(width 0.3556)
		(layer "F.Cu")
		(net "GND")
	)
	(segment
		(start 34.871914 -222.816674)
		(end 35.976814 -222.816674)
		(width 0.381)
		(layer "F.Cu")
		(net "GND")
	)
	(segment
		(start 39.420546 -233.016806)
		(end 38.315646 -233.016806)
		(width 0.381)
		(layer "F.Cu")
		(net "GND")
	)
	(segment
		(start 328.244962 -43.948096)
		(end 328.187812 -43.890946)
		(width 0.2032)
		(layer "F.Cu")
		(net "GND")
	)
	(segment
		(start 330.396596 -39.443152)
		(end 330.896976 -39.295324)
		(width 0.2032)
		(layer "F.Cu")
		(net "GND")
	)
	(segment
		(start 215.719914 -288.266632)
		(end 216.824814 -288.266632)
		(width 0.381)
		(layer "F.Cu")
		(net "GND")
	)
	(segment
		(start 11.135614 -224.516696)
		(end 12.240514 -224.516696)
		(width 0.381)
		(layer "F.Cu")
		(net "GND")
	)
	(segment
		(start 40.413178 -399.126456)
		(end 40.413178 -397.806672)
		(width 0.4572)
		(layer "F.Cu")
		(net "GND")
	)
	(segment
		(start 448.572382 -312.91657)
		(end 447.467482 -312.91657)
		(width 0.381)
		(layer "F.Cu")
		(net "GND")
	)
	(segment
		(start 272.273014 -210.916774)
		(end 271.168114 -210.916774)
		(width 0.381)
		(layer "F.Cu")
		(net "GND")
	)
	(segment
		(start 351.12198 -226.017582)
		(end 351.122234 -226.017328)
		(width 0.254)
		(layer "F.Cu")
		(net "GND")
	)
	(segment
		(start 117.278912 -222.76181)
		(end 117.279166 -222.761556)
		(width 0.254)
		(layer "F.Cu")
		(net "GND")
	)
	(segment
		(start 52.298346 -287.416748)
		(end 53.403246 -287.416748)
		(width 0.381)
		(layer "F.Cu")
		(net "GND")
	)
	(segment
		(start 100.942648 -268.84757)
		(end 100.942394 -268.847824)
		(width 0.2032)
		(layer "F.Cu")
		(net "GND")
	)
	(segment
		(start 53.403246 -210.916774)
		(end 52.082446 -210.916774)
		(width 0.381)
		(layer "F.Cu")
		(net "GND")
	)
	(segment
		(start 333.735934 -217.600276)
		(end 333.735934 -217.06459)
		(width 0.2032)
		(layer "F.Cu")
		(net "GND")
	)
	(segment
		(start 260.180582 -305.266598)
		(end 259.075682 -305.266598)
		(width 0.381)
		(layer "F.Cu")
		(net "GND")
	)
	(segment
		(start 173.900846 -242.3668)
		(end 172.795946 -242.3668)
		(width 0.381)
		(layer "F.Cu")
		(net "GND")
	)
	(segment
		(start 175.005746 -268.71676)
		(end 173.900846 -268.71676)
		(width 0.381)
		(layer "F.Cu")
		(net "GND")
	)
	(segment
		(start 171.562014 -224.516696)
		(end 170.457114 -224.516696)
		(width 0.381)
		(layer "F.Cu")
		(net "GND")
	)
	(segment
		(start 92.844366 -229.808532)
		(end 92.844366 -229.272846)
		(width 0.2032)
		(layer "F.Cu")
		(net "GND")
	)
	(segment
		(start 101.302312 -226.017582)
		(end 101.302566 -226.017328)
		(width 0.254)
		(layer "F.Cu")
		(net "GND")
	)
	(segment
		(start 410.853382 -204.116686)
		(end 411.958282 -204.116686)
		(width 0.381)
		(layer "F.Cu")
		(net "GND")
	)
	(segment
		(start 96.243648 -254.197612)
		(end 96.243648 -254.733044)
		(width 0.2032)
		(layer "F.Cu")
		(net "GND")
	)
	(segment
		(start 373.67718 -244.458744)
		(end 373.677434 -244.45849)
		(width 0.2032)
		(layer "F.Cu")
		(net "GND")
	)
	(segment
		(start 121.148094 -282.683966)
		(end 121.148094 -283.219906)
		(width 0.254)
		(layer "F.Cu")
		(net "GND")
	)
	(segment
		(start 254.975614 -317.166752)
		(end 256.080514 -317.166752)
		(width 0.381)
		(layer "F.Cu")
		(net "GND")
	)
	(segment
		(start 200.632314 -221.116652)
		(end 201.737214 -221.116652)
		(width 0.381)
		(layer "F.Cu")
		(net "GND")
	)
	(segment
		(start 133.346952 -12.495276)
		(end 133.346952 -13.600176)
		(width 0.3556)
		(layer "F.Cu")
		(net "GND")
	)
	(segment
		(start 185.544714 -284.866588)
		(end 184.439814 -284.866588)
		(width 0.381)
		(layer "F.Cu")
		(net "GND")
	)
	(segment
		(start 334.864456 -40.931846)
		(end 334.325468 -40.931846)
		(width 0.2032)
		(layer "F.Cu")
		(net "GND")
	)
	(segment
		(start 36.988496 -101.44379)
		(end 35.807396 -101.44379)
		(width 0.3556)
		(layer "F.Cu")
		(net "GND")
	)
	(segment
		(start 433.484782 -224.516696)
		(end 434.589682 -224.516696)
		(width 0.381)
		(layer "F.Cu")
		(net "GND")
	)
	(segment
		(start 348.772734 -217.600276)
		(end 348.772734 -217.064336)
		(width 0.2032)
		(layer "F.Cu")
		(net "GND")
	)
	(segment
		(start 19.784314 -250.866656)
		(end 20.889214 -250.866656)
		(width 0.381)
		(layer "F.Cu")
		(net "GND")
	)
	(segment
		(start 410.853382 -301.01667)
		(end 411.958282 -301.01667)
		(width 0.381)
		(layer "F.Cu")
		(net "GND")
	)
	(segment
		(start 275.268182 -272.966688)
		(end 274.163282 -272.966688)
		(width 0.381)
		(layer "F.Cu")
		(net "GND")
	)
	(segment
		(start 439.923682 -297.616626)
		(end 441.028582 -297.616626)
		(width 0.381)
		(layer "F.Cu")
		(net "GND")
	)
	(segment
		(start 38.315646 -300.166786)
		(end 37.210746 -300.166786)
		(width 0.381)
		(layer "F.Cu")
		(net "GND")
	)
	(segment
		(start 301.343314 -240.666778)
		(end 302.448214 -240.666778)
		(width 0.381)
		(layer "F.Cu")
		(net "GND")
	)
	(segment
		(start 371.327934 -250.155964)
		(end 371.32768 -250.15571)
		(width 0.2032)
		(layer "F.Cu")
		(net "GND")
	)
	(segment
		(start 285.150814 -283.166566)
		(end 286.255714 -283.166566)
		(width 0.381)
		(layer "F.Cu")
		(net "GND")
	)
	(segment
		(start 122.917712 -244.458744)
		(end 122.917712 -243.922804)
		(width 0.2032)
		(layer "F.Cu")
		(net "GND")
	)
	(segment
		(start 38.315646 -260.21665)
		(end 37.210746 -260.21665)
		(width 0.381)
		(layer "F.Cu")
		(net "GND")
	)
	(segment
		(start 286.033718 -367.757202)
		(end 286.033718 -368.428016)
		(width 0.381)
		(layer "F.Cu")
		(net "GND")
	)
	(segment
		(start 367.098834 -228.180646)
		(end 367.098834 -227.64496)
		(width 0.254)
		(layer "F.Cu")
		(net "GND")
	)
	(segment
		(start 444.472314 -287.416748)
		(end 445.577214 -287.416748)
		(width 0.381)
		(layer "F.Cu")
		(net "GND")
	)
	(segment
		(start 27.328114 -250.866656)
		(end 28.433014 -250.866656)
		(width 0.381)
		(layer "F.Cu")
		(net "GND")
	)
	(segment
		(start 91.434666 -228.45903)
		(end 91.434666 -228.99497)
		(width 0.2032)
		(layer "F.Cu")
		(net "GND")
	)
	(segment
		(start 57.503314 -261.066788)
		(end 56.398414 -261.066788)
		(width 0.381)
		(layer "F.Cu")
		(net "GND")
	)
	(segment
		(start 127.616712 -237.947454)
		(end 127.616712 -237.411768)
		(width 0.254)
		(layer "F.Cu")
		(net "GND")
	)
	(segment
		(start 381.775716 -282.405582)
		(end 381.775462 -282.405836)
		(width 0.254)
		(layer "F.Cu")
		(net "GND")
	)
	(segment
		(start 266.619482 -269.566644)
		(end 267.724382 -269.566644)
		(width 0.381)
		(layer "F.Cu")
		(net "GND")
	)
	(segment
		(start 358.280716 -272.639028)
		(end 358.280462 -272.639282)
		(width 0.254)
		(layer "F.Cu")
		(net "GND")
	)
	(segment
		(start 439.923682 -250.866656)
		(end 441.028582 -250.866656)
		(width 0.381)
		(layer "F.Cu")
		(net "GND")
	)
	(segment
		(start 350.345756 -335.541112)
		(end 350.000316 -335.886552)
		(width 0.2032)
		(layer "F.Cu")
		(net "GND")
	)
	(segment
		(start 126.207266 -248.528078)
		(end 126.207266 -247.992138)
		(width 0.2032)
		(layer "F.Cu")
		(net "GND")
	)
	(segment
		(start 137.484866 -235.506006)
		(end 137.014966 -235.783882)
		(width 0.254)
		(layer "F.Cu")
		(net "GND")
	)
	(segment
		(start 38.315646 -251.716794)
		(end 37.210746 -251.716794)
		(width 0.381)
		(layer "F.Cu")
		(net "GND")
	)
	(segment
		(start 63.942214 -291.666676)
		(end 65.047114 -291.666676)
		(width 0.381)
		(layer "F.Cu")
		(net "GND")
	)
	(segment
		(start 300.238414 -272.116804)
		(end 301.343314 -272.116804)
		(width 0.381)
		(layer "F.Cu")
		(net "GND")
	)
	(segment
		(start 266.619482 -219.41663)
		(end 267.724382 -219.41663)
		(width 0.381)
		(layer "F.Cu")
		(net "GND")
	)
	(segment
		(start 112.579912 -222.76181)
		(end 112.580166 -222.761556)
		(width 0.254)
		(layer "F.Cu")
		(net "GND")
	)
	(segment
		(start 186.649614 -226.216718)
		(end 185.544714 -226.216718)
		(width 0.381)
		(layer "F.Cu")
		(net "GND")
	)
	(segment
		(start 26.223214 -210.066636)
		(end 27.328114 -210.066636)
		(width 0.381)
		(layer "F.Cu")
		(net "GND")
	)
	(segment
		(start 422.945814 -304.416714)
		(end 421.840914 -304.416714)
		(width 0.381)
		(layer "F.Cu")
		(net "GND")
	)
	(segment
		(start 92.844112 -231.436418)
		(end 92.844366 -231.436164)
		(width 0.2032)
		(layer "F.Cu")
		(net "GND")
	)
	(segment
		(start 129.136648 -260.708902)
		(end 129.136648 -261.244588)
		(width 0.2032)
		(layer "F.Cu")
		(net "GND")
	)
	(segment
		(start 369.448334 -220.855794)
		(end 369.448334 -220.319854)
		(width 0.2032)
		(layer "F.Cu")
		(net "GND")
	)
	(segment
		(start 354.411534 -224.111566)
		(end 354.411534 -223.575626)
		(width 0.2032)
		(layer "F.Cu")
		(net "GND")
	)
	(segment
		(start 102.242112 -226.553268)
		(end 102.242112 -226.017582)
		(width 0.254)
		(layer "F.Cu")
		(net "GND")
	)
	(segment
		(start 188.988446 -251.716794)
		(end 187.883546 -251.716794)
		(width 0.381)
		(layer "F.Cu")
		(net "GND")
	)
	(segment
		(start 123.497848 -272.103342)
		(end 123.497594 -272.639282)
		(width 0.2032)
		(layer "F.Cu")
		(net "GND")
	)
	(segment
		(start 304.338482 -215.166702)
		(end 305.443382 -215.166702)
		(width 0.381)
		(layer "F.Cu")
		(net "GND")
	)
	(segment
		(start 380.365762 -263.150604)
		(end 380.365762 -263.68629)
		(width 0.2032)
		(layer "F.Cu")
		(net "GND")
	)
	(segment
		(start 289.250882 -284.866588)
		(end 290.355782 -284.866588)
		(width 0.381)
		(layer "F.Cu")
		(net "GND")
	)
	(segment
		(start 124.907294 -285.939484)
		(end 124.907294 -286.475424)
		(width 0.254)
		(layer "F.Cu")
		(net "GND")
	)
	(segment
		(start 202.971146 -289.11677)
		(end 204.076046 -289.11677)
		(width 0.381)
		(layer "F.Cu")
		(net "GND")
	)
	(segment
		(start 380.725934 -242.017042)
		(end 380.72568 -242.016788)
		(width 0.2032)
		(layer "F.Cu")
		(net "GND")
	)
	(segment
		(start 433.484782 -272.966688)
		(end 434.589682 -272.966688)
		(width 0.381)
		(layer "F.Cu")
		(net "GND")
	)
	(segment
		(start 125.377448 -281.869896)
		(end 125.377448 -282.405582)
		(width 0.254)
		(layer "F.Cu")
		(net "GND")
	)
	(segment
		(start 361.569762 -263.150604)
		(end 361.569762 -263.686544)
		(width 0.254)
		(layer "F.Cu")
		(net "GND")
	)
	(segment
		(start 86.265766 -239.57534)
		(end 86.735412 -239.853216)
		(width 0.254)
		(layer "F.Cu")
		(net "GND")
	)
	(segment
		(start 443.367414 -290.816792)
		(end 444.472314 -290.816792)
		(width 0.381)
		(layer "F.Cu")
		(net "GND")
	)
	(segment
		(start 341.839804 -335.89976)
		(end 341.839804 -336.115406)
		(width 0.2032)
		(layer "F.Cu")
		(net "GND")
	)
	(segment
		(start 443.367414 -307.816758)
		(end 444.472314 -307.816758)
		(width 0.381)
		(layer "F.Cu")
		(net "GND")
	)
	(segment
		(start 459.559914 -285.716726)
		(end 460.664814 -285.716726)
		(width 0.381)
		(layer "F.Cu")
		(net "GND")
	)
	(segment
		(start 366.738916 -281.869896)
		(end 366.738662 -282.405836)
		(width 0.254)
		(layer "F.Cu")
		(net "GND")
	)
	(segment
		(start 162.913314 -280.61666)
		(end 164.018214 -280.61666)
		(width 0.381)
		(layer "F.Cu")
		(net "GND")
	)
	(segment
		(start 127.726694 -260.430518)
		(end 127.726948 -260.430772)
		(width 0.254)
		(layer "F.Cu")
		(net "GND")
	)
	(segment
		(start 26.223214 -207.51673)
		(end 27.328114 -207.51673)
		(width 0.381)
		(layer "F.Cu")
		(net "GND")
	)
	(segment
		(start 188.988446 -229.616762)
		(end 187.883546 -229.616762)
		(width 0.381)
		(layer "F.Cu")
		(net "GND")
	)
	(segment
		(start 26.223214 -258.516628)
		(end 27.328114 -258.516628)
		(width 0.381)
		(layer "F.Cu")
		(net "GND")
	)
	(segment
		(start 43.520614 -284.866588)
		(end 42.415714 -284.866588)
		(width 0.381)
		(layer "F.Cu")
		(net "GND")
	)
	(segment
		(start 457.221082 -308.666642)
		(end 456.116182 -308.666642)
		(width 0.381)
		(layer "F.Cu")
		(net "GND")
	)
	(segment
		(start 93.783912 -216.250774)
		(end 93.784166 -216.25052)
		(width 0.254)
		(layer "F.Cu")
		(net "GND")
	)
	(segment
		(start 286.255714 -301.866808)
		(end 287.360614 -301.866808)
		(width 0.381)
		(layer "F.Cu")
		(net "GND")
	)
	(segment
		(start 293.799514 -236.416596)
		(end 292.694614 -236.416596)
		(width 0.381)
		(layer "F.Cu")
		(net "GND")
	)
	(segment
		(start 175.005746 -214.316564)
		(end 173.900846 -214.316564)
		(width 0.381)
		(layer "F.Cu")
		(net "GND")
	)
	(segment
		(start 300.238414 -240.666778)
		(end 301.343314 -240.666778)
		(width 0.381)
		(layer "F.Cu")
		(net "GND")
	)
	(segment
		(start 297.899582 -275.516594)
		(end 299.004482 -275.516594)
		(width 0.381)
		(layer "F.Cu")
		(net "GND")
	)
	(segment
		(start 272.273014 -292.516814)
		(end 271.168114 -292.516814)
		(width 0.381)
		(layer "F.Cu")
		(net "GND")
	)
	(segment
		(start 386.83438 -234.69219)
		(end 387.30428 -234.970066)
		(width 0.254)
		(layer "F.Cu")
		(net "GND")
	)
	(segment
		(start 45.657008 -10.16508)
		(end 45.657008 -11.26998)
		(width 0.3556)
		(layer "F.Cu")
		(net "GND")
	)
	(segment
		(start 462.555082 -267.866622)
		(end 463.659982 -267.866622)
		(width 0.381)
		(layer "F.Cu")
		(net "GND")
	)
	(segment
		(start 384.485134 -240.389156)
		(end 384.485134 -239.85347)
		(width 0.254)
		(layer "F.Cu")
		(net "GND")
	)
	(segment
		(start 37.330634 -108.555282)
		(end 37.940234 -108.555282)
		(width 0.3556)
		(layer "F.Cu")
		(net "GND")
	)
	(segment
		(start 349.352362 -268.033754)
		(end 349.352362 -268.569694)
		(width 0.2032)
		(layer "F.Cu")
		(net "GND")
	)
	(segment
		(start 113.629694 -266.405868)
		(end 113.629694 -266.941808)
		(width 0.254)
		(layer "F.Cu")
		(net "GND")
	)
	(segment
		(start 194.193414 -241.516662)
		(end 193.088514 -241.516662)
		(width 0.381)
		(layer "F.Cu")
		(net "GND")
	)
	(segment
		(start 254.975614 -201.56678)
		(end 256.080514 -201.56678)
		(width 0.381)
		(layer "F.Cu")
		(net "GND")
	)
	(segment
		(start 173.900846 -250.016772)
		(end 175.005746 -250.016772)
		(width 0.381)
		(layer "F.Cu")
		(net "GND")
	)
	(segment
		(start 42.415714 -277.216616)
		(end 41.310814 -277.216616)
		(width 0.381)
		(layer "F.Cu")
		(net "GND")
	)
	(segment
		(start 102.39502 -339.334602)
		(end 102.355142 -339.294724)
		(width 0.381)
		(layer "F.Cu")
		(net "GND")
	)
	(segment
		(start 162.913314 -233.86669)
		(end 164.018214 -233.86669)
		(width 0.381)
		(layer "F.Cu")
		(net "GND")
	)
	(segment
		(start 420.736014 -273.816572)
		(end 421.840914 -273.816572)
		(width 0.381)
		(layer "F.Cu")
		(net "GND")
	)
	(segment
		(start 56.398414 -204.116686)
		(end 57.503314 -204.116686)
		(width 0.381)
		(layer "F.Cu")
		(net "GND")
	)
	(segment
		(start 119.158512 -222.76181)
		(end 119.158766 -222.761556)
		(width 0.254)
		(layer "F.Cu")
		(net "GND")
	)
	(segment
		(start 19.784314 -305.266598)
		(end 18.679414 -305.266598)
		(width 0.381)
		(layer "F.Cu")
		(net "GND")
	)
	(segment
		(start 445.577214 -261.916672)
		(end 444.472314 -261.916672)
		(width 0.381)
		(layer "F.Cu")
		(net "GND")
	)
	(segment
		(start 195.427346 -240.666778)
		(end 196.532246 -240.666778)
		(width 0.381)
		(layer "F.Cu")
		(net "GND")
	)
	(segment
		(start 59.842146 -233.016806)
		(end 60.947046 -233.016806)
		(width 0.381)
		(layer "F.Cu")
		(net "GND")
	)
	(segment
		(start 459.559914 -248.31675)
		(end 458.455014 -248.31675)
		(width 0.381)
		(layer "F.Cu")
		(net "GND")
	)
	(segment
		(start 91.434666 -246.900446)
		(end 91.434412 -246.900192)
		(width 0.2032)
		(layer "F.Cu")
		(net "GND")
	)
	(segment
		(start 191.816482 -435.003956)
		(end 191.816482 -434.3019)
		(width 0.3556)
		(layer "F.Cu")
		(net "GND")
	)
	(segment
		(start 59.842146 -216.016586)
		(end 60.947046 -216.016586)
		(width 0.381)
		(layer "F.Cu")
		(net "GND")
	)
	(segment
		(start 208.176114 -205.816708)
		(end 209.281014 -205.816708)
		(width 0.381)
		(layer "F.Cu")
		(net "GND")
	)
	(segment
		(start 275.268182 -282.316682)
		(end 274.163282 -282.316682)
		(width 0.381)
		(layer "F.Cu")
		(net "GND")
	)
	(segment
		(start 29.666946 -203.266802)
		(end 30.771846 -203.266802)
		(width 0.381)
		(layer "F.Cu")
		(net "GND")
	)
	(segment
		(start 347.363034 -237.947454)
		(end 347.363034 -237.411514)
		(width 0.254)
		(layer "F.Cu")
		(net "GND")
	)
	(segment
		(start 445.577214 -270.416782)
		(end 444.472314 -270.416782)
		(width 0.381)
		(layer "F.Cu")
		(net "GND")
	)
	(segment
		(start 188.988446 -225.36658)
		(end 190.093346 -225.36658)
		(width 0.381)
		(layer "F.Cu")
		(net "GND")
	)
	(segment
		(start 56.398414 -286.56661)
		(end 57.503314 -286.56661)
		(width 0.381)
		(layer "F.Cu")
		(net "GND")
	)
	(segment
		(start 106.001566 -220.041724)
		(end 106.001566 -219.506038)
		(width 0.254)
		(layer "F.Cu")
		(net "GND")
	)
	(segment
		(start 158.813246 -197.316598)
		(end 159.918146 -197.316598)
		(width 0.381)
		(layer "F.Cu")
		(net "GND")
	)
	(segment
		(start 443.367414 -273.816572)
		(end 444.472314 -273.816572)
		(width 0.381)
		(layer "F.Cu")
		(net "GND")
	)
	(segment
		(start 331.897482 -57.904888)
		(end 332.012798 -58.020204)
		(width 0.2032)
		(layer "F.Cu")
		(net "GND")
	)
	(segment
		(start 366.268762 -269.66164)
		(end 366.269016 -270.167862)
		(width 0.254)
		(layer "F.Cu")
		(net "GND")
	)
	(segment
		(start 267.724382 -216.866724)
		(end 268.829282 -216.866724)
		(width 0.381)
		(layer "F.Cu")
		(net "GND")
	)
	(segment
		(start 166.357046 -206.666592)
		(end 167.749728 -206.666592)
		(width 0.381)
		(layer "F.Cu")
		(net "GND")
	)
	(segment
		(start 346.964254 -25.757124)
		(end 346.964254 -25.06218)
		(width 0.381)
		(layer "F.Cu")
		(net "GND")
	)
	(segment
		(start 133.255512 -228.1809)
		(end 133.255766 -228.180646)
		(width 0.2032)
		(layer "F.Cu")
		(net "GND")
	)
	(segment
		(start 424.166792 -11.26998)
		(end 424.166792 -12.37488)
		(width 0.3556)
		(layer "F.Cu")
		(net "GND")
	)
	(segment
		(start 271.168114 -260.21665)
		(end 270.063214 -260.21665)
		(width 0.381)
		(layer "F.Cu")
		(net "GND")
	)
	(segment
		(start 113.519712 -249.342148)
		(end 113.519712 -248.80697)
		(width 0.254)
		(layer "F.Cu")
		(net "GND")
	)
	(segment
		(start 57.503314 -219.41663)
		(end 58.824114 -219.41663)
		(width 0.381)
		(layer "F.Cu")
		(net "GND")
	)
	(segment
		(start 178.000914 -266.1666)
		(end 176.896014 -266.1666)
		(width 0.381)
		(layer "F.Cu")
		(net "GND")
	)
	(segment
		(start 181.444646 -295.06672)
		(end 180.339746 -295.06672)
		(width 0.381)
		(layer "F.Cu")
		(net "GND")
	)
	(segment
		(start 129.136648 -259.093462)
		(end 129.136394 -259.616956)
		(width 0.2032)
		(layer "F.Cu")
		(net "GND")
	)
	(segment
		(start 295.049702 -423.954448)
		(end 295.602406 -424.507152)
		(width 0.3556)
		(layer "F.Cu")
		(net "GND")
	)
	(segment
		(start 308.887114 -217.716608)
		(end 310.207914 -217.716608)
		(width 0.381)
		(layer "F.Cu")
		(net "GND")
	)
	(segment
		(start 177.108104 -51.299872)
		(end 178.289204 -51.299872)
		(width 0.254)
		(layer "F.Cu")
		(net "GND")
	)
	(segment
		(start 344.07348 -245.272306)
		(end 344.07348 -244.73662)
		(width 0.2032)
		(layer "F.Cu")
		(net "GND")
	)
	(segment
		(start 343.006934 -40.931592)
		(end 343.005156 -40.931846)
		(width 0.254)
		(layer "F.Cu")
		(net "GND")
	)
	(segment
		(start 170.457114 -294.216582)
		(end 171.765214 -294.216582)
		(width 0.381)
		(layer "F.Cu")
		(net "GND")
	)
	(segment
		(start 293.799514 -212.616796)
		(end 292.694614 -212.616796)
		(width 0.381)
		(layer "F.Cu")
		(net "GND")
	)
	(segment
		(start 346.893134 -217.600276)
		(end 346.893134 -217.064336)
		(width 0.2032)
		(layer "F.Cu")
		(net "GND")
	)
	(segment
		(start 29.031692 -410.784548)
		(end 29.666692 -410.784548)
		(width 0.3556)
		(layer "F.Cu")
		(net "GND")
	)
	(segment
		(start 52.298346 -300.166786)
		(end 53.403246 -300.166786)
		(width 0.381)
		(layer "F.Cu")
		(net "GND")
	)
	(segment
		(start 362.399834 -223.297496)
		(end 362.399834 -222.761556)
		(width 0.254)
		(layer "F.Cu")
		(net "GND")
	)
	(segment
		(start 138.064494 -282.683966)
		(end 138.064494 -283.219144)
		(width 0.254)
		(layer "F.Cu")
		(net "GND")
	)
	(segment
		(start 331.608176 -54.089046)
		(end 331.067918 -54.089046)
		(width 0.2032)
		(layer "F.Cu")
		(net "GND")
	)
	(segment
		(start 181.444646 -234.716574)
		(end 182.549546 -234.716574)
		(width 0.381)
		(layer "F.Cu")
		(net "GND")
	)
	(segment
		(start 208.176114 -202.416664)
		(end 209.281014 -202.416664)
		(width 0.381)
		(layer "F.Cu")
		(net "GND")
	)
	(segment
		(start 98.482912 -233.064304)
		(end 98.482912 -232.528364)
		(width 0.2032)
		(layer "F.Cu")
		(net "GND")
	)
	(segment
		(start 420.736014 -212.616796)
		(end 421.840914 -212.616796)
		(width 0.381)
		(layer "F.Cu")
		(net "GND")
	)
	(segment
		(start 245.760494 -90.651584)
		(end 246.384572 -90.651584)
		(width 0.3556)
		(layer "F.Cu")
		(net "GND")
	)
	(segment
		(start 130.546094 -285.939484)
		(end 130.546094 -286.475424)
		(width 0.2032)
		(layer "F.Cu")
		(net "GND")
	)
	(segment
		(start 341.364316 -284.033468)
		(end 341.364062 -284.033722)
		(width 0.254)
		(layer "F.Cu")
		(net "GND")
	)
	(segment
		(start 27.328114 -219.41663)
		(end 28.433014 -219.41663)
		(width 0.381)
		(layer "F.Cu")
		(net "GND")
	)
	(segment
		(start 275.268182 -232.166668)
		(end 274.163282 -232.166668)
		(width 0.381)
		(layer "F.Cu")
		(net "GND")
	)
	(segment
		(start 276.373082 -294.216582)
		(end 275.268182 -294.216582)
		(width 0.381)
		(layer "F.Cu")
		(net "GND")
	)
	(segment
		(start 339.711538 -45.249846)
		(end 339.300058 -45.249846)
		(width 0.2032)
		(layer "F.Cu")
		(net "GND")
	)
	(segment
		(start 49.755552 -155.586684)
		(end 49.755552 -156.228034)
		(width 0.381)
		(layer "F.Cu")
		(net "GND")
	)
	(segment
		(start 290.355782 -204.116686)
		(end 291.460682 -204.116686)
		(width 0.381)
		(layer "F.Cu")
		(net "GND")
	)
	(segment
		(start 196.532246 -220.266768)
		(end 195.427346 -220.266768)
		(width 0.381)
		(layer "F.Cu")
		(net "GND")
	)
	(segment
		(start 45.859446 -216.016586)
		(end 46.964346 -216.016586)
		(width 0.381)
		(layer "F.Cu")
		(net "GND")
	)
	(segment
		(start 285.150814 -201.56678)
		(end 286.255714 -201.56678)
		(width 0.381)
		(layer "F.Cu")
		(net "GND")
	)
	(segment
		(start 372.267734 -232.250488)
		(end 372.26748 -232.250234)
		(width 0.254)
		(layer "F.Cu")
		(net "GND")
	)
	(segment
		(start 290.355782 -202.416664)
		(end 291.460682 -202.416664)
		(width 0.381)
		(layer "F.Cu")
		(net "GND")
	)
	(segment
		(start 135.245094 -255.011682)
		(end 135.245094 -255.547622)
		(width 0.2032)
		(layer "F.Cu")
		(net "GND")
	)
	(segment
		(start 345.013534 -245.27256)
		(end 345.013534 -244.73662)
		(width 0.2032)
		(layer "F.Cu")
		(net "GND")
	)
	(segment
		(start 385.424934 -248.528078)
		(end 384.96367 -248.794524)
		(width 0.254)
		(layer "F.Cu")
		(net "GND")
	)
	(segment
		(start 100.472494 -279.96388)
		(end 100.472748 -279.964134)
		(width 0.254)
		(layer "F.Cu")
		(net "GND")
	)
	(segment
		(start 346.559378 -38.2905)
		(end 347.214698 -38.2905)
		(width 0.2032)
		(layer "F.Cu")
		(net "GND")
	)
	(segment
		(start 312.987182 -194.766692)
		(end 314.092082 -194.766692)
		(width 0.381)
		(layer "F.Cu")
		(net "GND")
	)
	(segment
		(start 272.273014 -278.066754)
		(end 271.168114 -278.066754)
		(width 0.381)
		(layer "F.Cu")
		(net "GND")
	)
	(segment
		(start 204.076046 -234.716574)
		(end 205.180946 -234.716574)
		(width 0.381)
		(layer "F.Cu")
		(net "GND")
	)
	(segment
		(start 361.45978 -241.203226)
		(end 361.45978 -240.66754)
		(width 0.254)
		(layer "F.Cu")
		(net "GND")
	)
	(segment
		(start 335.725262 -287.28924)
		(end 335.725262 -286.7533)
		(width 0.254)
		(layer "F.Cu")
		(net "GND")
	)
	(segment
		(start 429.384714 -285.716726)
		(end 430.489614 -285.716726)
		(width 0.381)
		(layer "F.Cu")
		(net "GND")
	)
	(segment
		(start 175.005746 -233.016806)
		(end 173.900846 -233.016806)
		(width 0.381)
		(layer "F.Cu")
		(net "GND")
	)
	(segment
		(start 263.624314 -244.916706)
		(end 264.729214 -244.916706)
		(width 0.381)
		(layer "F.Cu")
		(net "GND")
	)
	(segment
		(start 276.373082 -233.86669)
		(end 275.268182 -233.86669)
		(width 0.381)
		(layer "F.Cu")
		(net "GND")
	)
	(segment
		(start 354.881434 -220.041724)
		(end 354.881434 -219.506038)
		(width 0.254)
		(layer "F.Cu")
		(net "GND")
	)
	(segment
		(start 453.121014 -225.36658)
		(end 452.016114 -225.36658)
		(width 0.381)
		(layer "F.Cu")
		(net "GND")
	)
	(segment
		(start 166.357046 -285.716726)
		(end 165.140894 -285.716726)
		(width 0.381)
		(layer "F.Cu")
		(net "GND")
	)
	(segment
		(start 164.018214 -262.76681)
		(end 162.913314 -262.76681)
		(width 0.381)
		(layer "F.Cu")
		(net "GND")
	)
	(segment
		(start 383.07518 -232.528618)
		(end 383.075434 -232.528364)
		(width 0.2032)
		(layer "F.Cu")
		(net "GND")
	)
	(segment
		(start 276.373082 -272.966688)
		(end 275.268182 -272.966688)
		(width 0.381)
		(layer "F.Cu")
		(net "GND")
	)
	(segment
		(start 97.073466 -245.27256)
		(end 97.073466 -244.73662)
		(width 0.2032)
		(layer "F.Cu")
		(net "GND")
	)
	(segment
		(start 88.145366 -234.69219)
		(end 88.145366 -234.15625)
		(width 0.254)
		(layer "F.Cu")
		(net "GND")
	)
	(segment
		(start 42.415714 -284.866588)
		(end 41.310814 -284.866588)
		(width 0.381)
		(layer "F.Cu")
		(net "GND")
	)
	(segment
		(start 42.415714 -204.116686)
		(end 41.310814 -204.116686)
		(width 0.381)
		(layer "F.Cu")
		(net "GND")
	)
	(segment
		(start 240.85042 -247.079008)
		(end 240.51387 -247.415558)
		(width 0.3556)
		(layer "F.Cu")
		(net "GND")
	)
	(segment
		(start 304.338482 -310.366664)
		(end 305.443382 -310.366664)
		(width 0.381)
		(layer "F.Cu")
		(net "GND")
	)
	(segment
		(start 285.150814 -248.31675)
		(end 286.255714 -248.31675)
		(width 0.381)
		(layer "F.Cu")
		(net "GND")
	)
	(segment
		(start 444.472314 -236.416596)
		(end 445.577214 -236.416596)
		(width 0.381)
		(layer "F.Cu")
		(net "GND")
	)
	(segment
		(start 211.619846 -270.416782)
		(end 212.724746 -270.416782)
		(width 0.381)
		(layer "F.Cu")
		(net "GND")
	)
	(segment
		(start 449.677282 -247.466612)
		(end 448.572382 -247.466612)
		(width 0.381)
		(layer "F.Cu")
		(net "GND")
	)
	(segment
		(start 304.338482 -230.466646)
		(end 305.443382 -230.466646)
		(width 0.381)
		(layer "F.Cu")
		(net "GND")
	)
	(segment
		(start 376.49658 -228.1809)
		(end 376.49658 -227.64496)
		(width 0.2032)
		(layer "F.Cu")
		(net "GND")
	)
	(segment
		(start 336.555334 -217.06459)
		(end 336.55508 -217.064336)
		(width 0.2032)
		(layer "F.Cu")
		(net "GND")
	)
	(segment
		(start 63.942214 -249.166634)
		(end 65.047114 -249.166634)
		(width 0.381)
		(layer "F.Cu")
		(net "GND")
	)
	(segment
		(start 52.298346 -290.816792)
		(end 53.403246 -290.816792)
		(width 0.381)
		(layer "F.Cu")
		(net "GND")
	)
	(segment
		(start 100.942648 -255.825498)
		(end 100.942648 -256.361438)
		(width 0.2032)
		(layer "F.Cu")
		(net "GND")
	)
	(segment
		(start 342.304116 -269.383256)
		(end 342.303862 -269.38351)
		(width 0.2032)
		(layer "F.Cu")
		(net "GND")
	)
	(segment
		(start 342.66378 -231.436418)
		(end 342.664034 -231.436164)
		(width 0.2032)
		(layer "F.Cu")
		(net "GND")
	)
	(segment
		(start 281.707082 -316.316614)
		(end 282.811982 -316.316614)
		(width 0.381)
		(layer "F.Cu")
		(net "GND")
	)
	(segment
		(start 364.389162 -284.847284)
		(end 364.389416 -284.847538)
		(width 0.254)
		(layer "F.Cu")
		(net "GND")
	)
	(segment
		(start 93.424248 -257.988816)
		(end 93.423994 -257.98907)
		(width 0.2032)
		(layer "F.Cu")
		(net "GND")
	)
	(segment
		(start 357.70058 -229.808786)
		(end 357.700834 -229.808532)
		(width 0.2032)
		(layer "F.Cu")
		(net "GND")
	)
	(segment
		(start 309.71617 -56.445658)
		(end 309.01894 -56.445658)
		(width 0.3556)
		(layer "F.Cu")
		(net "GND")
	)
	(segment
		(start 444.472314 -276.366732)
		(end 445.577214 -276.366732)
		(width 0.381)
		(layer "F.Cu")
		(net "GND")
	)
	(segment
		(start 184.439814 -264.466578)
		(end 185.544714 -264.466578)
		(width 0.381)
		(layer "F.Cu")
		(net "GND")
	)
	(segment
		(start 348.412562 -270.197326)
		(end 348.412816 -270.19758)
		(width 0.2032)
		(layer "F.Cu")
		(net "GND")
	)
	(segment
		(start 34.871914 -316.316614)
		(end 35.976814 -316.316614)
		(width 0.381)
		(layer "F.Cu")
		(net "GND")
	)
	(segment
		(start 59.842146 -204.96657)
		(end 60.947046 -204.96657)
		(width 0.381)
		(layer "F.Cu")
		(net "GND")
	)
	(segment
		(start 348.302834 -228.180646)
		(end 348.302834 -227.64496)
		(width 0.2032)
		(layer "F.Cu")
		(net "GND")
	)
	(segment
		(start 374.726962 -264.778236)
		(end 374.726962 -265.314176)
		(width 0.2032)
		(layer "F.Cu")
		(net "GND")
	)
	(segment
		(start 132.315712 -230.900478)
		(end 132.315712 -231.436418)
		(width 0.2032)
		(layer "F.Cu")
		(net "GND")
	)
	(segment
		(start 26.223214 -261.066788)
		(end 27.328114 -261.066788)
		(width 0.381)
		(layer "F.Cu")
		(net "GND")
	)
	(segment
		(start 94.723712 -249.342148)
		(end 94.723712 -248.806208)
		(width 0.2032)
		(layer "F.Cu")
		(net "GND")
	)
	(segment
		(start 285.150814 -313.766708)
		(end 286.255714 -313.766708)
		(width 0.381)
		(layer "F.Cu")
		(net "GND")
	)
	(segment
		(start 185.544714 -245.76659)
		(end 186.649614 -245.76659)
		(width 0.381)
		(layer "F.Cu")
		(net "GND")
	)
	(segment
		(start 419.636702 -133.94055)
		(end 419.826186 -134.130034)
		(width 0.381)
		(layer "F.Cu")
		(net "GND")
	)
	(segment
		(start 359.58018 -226.553268)
		(end 359.58018 -226.017582)
		(width 0.254)
		(layer "F.Cu")
		(net "GND")
	)
	(segment
		(start 14.579346 -296.766742)
		(end 15.684246 -296.766742)
		(width 0.381)
		(layer "F.Cu")
		(net "GND")
	)
	(segment
		(start 355.461316 -281.869896)
		(end 355.461316 -282.405582)
		(width 0.254)
		(layer "F.Cu")
		(net "GND")
	)
	(segment
		(start 364.389162 -282.683966)
		(end 364.389162 -283.219652)
		(width 0.254)
		(layer "F.Cu")
		(net "GND")
	)
	(segment
		(start 8.140446 -283.166566)
		(end 9.245346 -283.166566)
		(width 0.381)
		(layer "F.Cu")
		(net "GND")
	)
	(segment
		(start 381.19558 -216.78646)
		(end 381.19558 -216.250774)
		(width 0.254)
		(layer "F.Cu")
		(net "GND")
	)
	(segment
		(start 276.373082 -271.266666)
		(end 275.268182 -271.266666)
		(width 0.381)
		(layer "F.Cu")
		(net "GND")
	)
	(segment
		(start 278.711914 -204.96657)
		(end 279.816814 -204.96657)
		(width 0.381)
		(layer "F.Cu")
		(net "GND")
	)
	(segment
		(start 170.457114 -266.1666)
		(end 171.562014 -266.1666)
		(width 0.381)
		(layer "F.Cu")
		(net "GND")
	)
	(segment
		(start 276.373082 -297.616626)
		(end 275.268182 -297.616626)
		(width 0.381)
		(layer "F.Cu")
		(net "GND")
	)
	(segment
		(start 289.250882 -275.516594)
		(end 290.355782 -275.516594)
		(width 0.381)
		(layer "F.Cu")
		(net "GND")
	)
	(segment
		(start 135.135366 -247.714008)
		(end 135.135366 -247.178322)
		(width 0.2032)
		(layer "F.Cu")
		(net "GND")
	)
	(segment
		(start 195.427346 -229.616762)
		(end 196.532246 -229.616762)
		(width 0.381)
		(layer "F.Cu")
		(net "GND")
	)
	(segment
		(start 200.632314 -305.266598)
		(end 201.737214 -305.266598)
		(width 0.381)
		(layer "F.Cu")
		(net "GND")
	)
	(segment
		(start 348.882716 -263.96442)
		(end 348.882716 -264.500106)
		(width 0.254)
		(layer "F.Cu")
		(net "GND")
	)
	(segment
		(start 385.534662 -262.336534)
		(end 385.534662 -262.872474)
		(width 0.254)
		(layer "F.Cu")
		(net "GND")
	)
	(segment
		(start 418.90188 -157.032198)
		(end 418.90188 -157.648148)
		(width 0.3556)
		(layer "F.Cu")
		(net "GND")
	)
	(segment
		(start 118.798848 -280.242264)
		(end 118.798848 -280.77795)
		(width 0.254)
		(layer "F.Cu")
		(net "GND")
	)
	(segment
		(start 131.016248 -287.288986)
		(end 131.015994 -287.28924)
		(width 0.254)
		(layer "F.Cu")
		(net "GND")
	)
	(segment
		(start 12.240514 -198.166736)
		(end 13.345414 -198.166736)
		(width 0.381)
		(layer "F.Cu")
		(net "GND")
	)
	(segment
		(start 306.963572 -44.948348)
		(end 306.963572 -44.237148)
		(width 0.381)
		(layer "F.Cu")
		(net "GND")
	)
	(segment
		(start 165.252146 -233.016806)
		(end 166.357046 -233.016806)
		(width 0.381)
		(layer "F.Cu")
		(net "GND")
	)
	(segment
		(start 193.088514 -272.966688)
		(end 194.193414 -272.966688)
		(width 0.381)
		(layer "F.Cu")
		(net "GND")
	)
	(segment
		(start 204.076046 -298.466764)
		(end 205.180946 -298.466764)
		(width 0.381)
		(layer "F.Cu")
		(net "GND")
	)
	(segment
		(start 380.835916 -270.475456)
		(end 380.835662 -271.011396)
		(width 0.2032)
		(layer "F.Cu")
		(net "GND")
	)
	(segment
		(start 92.954348 -271.289526)
		(end 92.954348 -271.825212)
		(width 0.2032)
		(layer "F.Cu")
		(net "GND")
	)
	(segment
		(start 343.133934 -250.155964)
		(end 343.13368 -250.15571)
		(width 0.2032)
		(layer "F.Cu")
		(net "GND")
	)
	(segment
		(start 60.947046 -273.816572)
		(end 62.267846 -273.816572)
		(width 0.381)
		(layer "F.Cu")
		(net "GND")
	)
	(segment
		(start 144.181576 -64.051942)
		(end 143.495776 -64.051942)
		(width 0.3556)
		(layer "F.Cu")
		(net "GND")
	)
	(segment
		(start 211.619846 -309.51678)
		(end 210.514946 -309.51678)
		(width 0.381)
		(layer "F.Cu")
		(net "GND")
	)
	(segment
		(start 122.558048 -254.733298)
		(end 122.557794 -254.733552)
		(width 0.254)
		(layer "F.Cu")
		(net "GND")
	)
	(segment
		(start 87.211916 -98.548952)
		(end 86.704424 -98.548952)
		(width 0.3556)
		(layer "F.Cu")
		(net "GND")
	)
	(segment
		(start 338.544916 -276.986492)
		(end 338.544916 -277.522432)
		(width 0.2032)
		(layer "F.Cu")
		(net "GND")
	)
	(segment
		(start 60.947046 -214.316564)
		(end 62.051946 -214.316564)
		(width 0.381)
		(layer "F.Cu")
		(net "GND")
	)
	(segment
		(start 97.543112 -229.808786)
		(end 97.543366 -229.808532)
		(width 0.2032)
		(layer "F.Cu")
		(net "GND")
	)
	(segment
		(start 212.376004 -15.920974)
		(end 211.972144 -15.517114)
		(width 0.3556)
		(layer "F.Cu")
		(net "GND")
	)
	(segment
		(start 305.443382 -226.216718)
		(end 306.548282 -226.216718)
		(width 0.381)
		(layer "F.Cu")
		(net "GND")
	)
	(segment
		(start 113.519712 -226.017582)
		(end 113.519966 -226.017328)
		(width 0.254)
		(layer "F.Cu")
		(net "GND")
	)
	(segment
		(start 127.726694 -255.011682)
		(end 128.666748 -255.547622)
		(width 0.2032)
		(layer "F.Cu")
		(net "GND")
	)
	(segment
		(start 256.080514 -246.616728)
		(end 257.185414 -246.616728)
		(width 0.381)
		(layer "F.Cu")
		(net "GND")
	)
	(segment
		(start 95.303848 -287.288986)
		(end 95.303594 -287.28924)
		(width 0.254)
		(layer "F.Cu")
		(net "GND")
	)
	(segment
		(start 369.23218 -71.42226)
		(end 369.23218 -70.65518)
		(width 0.3556)
		(layer "F.Cu")
		(net "GND")
	)
	(segment
		(start 456.737466 -103.646224)
		(end 456.051666 -103.646224)
		(width 0.3556)
		(layer "F.Cu")
		(net "GND")
	)
	(segment
		(start 296.794682 -239.81664)
		(end 297.899582 -239.81664)
		(width 0.381)
		(layer "F.Cu")
		(net "GND")
	)
	(segment
		(start 190.093346 -250.016772)
		(end 188.988446 -250.016772)
		(width 0.381)
		(layer "F.Cu")
		(net "GND")
	)
	(segment
		(start 374.147334 -246.900446)
		(end 374.14708 -246.900192)
		(width 0.2032)
		(layer "F.Cu")
		(net "GND")
	)
	(segment
		(start 409.748482 -299.316648)
		(end 410.853382 -299.316648)
		(width 0.381)
		(layer "F.Cu")
		(net "GND")
	)
	(segment
		(start 194.30873 -357.165148)
		(end 194.33413 -357.139748)
		(width 0.3556)
		(layer "F.Cu")
		(net "GND")
	)
	(segment
		(start 52.082446 -273.816572)
		(end 53.403246 -273.816572)
		(width 0.381)
		(layer "F.Cu")
		(net "GND")
	)
	(segment
		(start 12.240514 -241.516662)
		(end 13.345414 -241.516662)
		(width 0.381)
		(layer "F.Cu")
		(net "GND")
	)
	(segment
		(start 267.724382 -278.916638)
		(end 268.829282 -278.916638)
		(width 0.381)
		(layer "F.Cu")
		(net "GND")
	)
	(segment
		(start 296.794682 -238.116618)
		(end 297.899582 -238.116618)
		(width 0.381)
		(layer "F.Cu")
		(net "GND")
	)
	(segment
		(start 14.426946 -392.199876)
		(end 15.036546 -392.199876)
		(width 0.3556)
		(layer "F.Cu")
		(net "GND")
	)
	(segment
		(start 19.784314 -215.166702)
		(end 18.679414 -215.166702)
		(width 0.381)
		(layer "F.Cu")
		(net "GND")
	)
	(segment
		(start 413.192214 -206.666592)
		(end 414.297114 -206.666592)
		(width 0.381)
		(layer "F.Cu")
		(net "GND")
	)
	(segment
		(start 343.00541 -48.449992)
		(end 343.005156 -48.450246)
		(width 0.254)
		(layer "F.Cu")
		(net "GND")
	)
	(segment
		(start 341.72398 -226.017582)
		(end 341.724234 -226.017328)
		(width 0.254)
		(layer "F.Cu")
		(net "GND")
	)
	(segment
		(start 190.093346 -204.96657)
		(end 188.988446 -204.96657)
		(width 0.381)
		(layer "F.Cu")
		(net "GND")
	)
	(segment
		(start 104.231948 -271.289526)
		(end 104.231948 -271.825212)
		(width 0.2032)
		(layer "F.Cu")
		(net "GND")
	)
	(segment
		(start 363.80928 -232.250234)
		(end 363.80928 -231.714548)
		(width 0.2032)
		(layer "F.Cu")
		(net "GND")
	)
	(segment
		(start 444.472314 -206.666592)
		(end 443.367414 -206.666592)
		(width 0.381)
		(layer "F.Cu")
		(net "GND")
	)
	(segment
		(start 453.121014 -236.416596)
		(end 452.016114 -236.416596)
		(width 0.381)
		(layer "F.Cu")
		(net "GND")
	)
	(segment
		(start 134.305294 -275.080476)
		(end 134.305548 -275.08073)
		(width 0.2032)
		(layer "F.Cu")
		(net "GND")
	)
	(segment
		(start 272.273014 -265.316716)
		(end 271.168114 -265.316716)
		(width 0.381)
		(layer "F.Cu")
		(net "GND")
	)
	(segment
		(start 29.666946 -204.96657)
		(end 30.771846 -204.96657)
		(width 0.381)
		(layer "F.Cu")
		(net "GND")
	)
	(segment
		(start 262.519414 -311.216802)
		(end 263.624314 -311.216802)
		(width 0.381)
		(layer "F.Cu")
		(net "GND")
	)
	(segment
		(start 127.616966 -220.041724)
		(end 127.616966 -219.506038)
		(width 0.254)
		(layer "F.Cu")
		(net "GND")
	)
	(segment
		(start 60.947046 -250.016772)
		(end 62.051946 -250.016772)
		(width 0.381)
		(layer "F.Cu")
		(net "GND")
	)
	(segment
		(start 19.784314 -289.966654)
		(end 20.889214 -289.966654)
		(width 0.381)
		(layer "F.Cu")
		(net "GND")
	)
	(segment
		(start 266.619482 -310.366664)
		(end 267.724382 -310.366664)
		(width 0.381)
		(layer "F.Cu")
		(net "GND")
	)
	(segment
		(start 419.502082 -249.166634)
		(end 418.397182 -249.166634)
		(width 0.381)
		(layer "F.Cu")
		(net "GND")
	)
	(segment
		(start 29.694378 -102.761034)
		(end 29.084778 -102.761034)
		(width 0.3556)
		(layer "F.Cu")
		(net "GND")
	)
	(segment
		(start 96.603312 -216.250774)
		(end 96.603566 -216.25052)
		(width 0.254)
		(layer "F.Cu")
		(net "GND")
	)
	(segment
		(start 459.559914 -225.36658)
		(end 458.455014 -225.36658)
		(width 0.381)
		(layer "F.Cu")
		(net "GND")
	)
	(segment
		(start 348.412562 -259.894832)
		(end 348.412562 -260.430518)
		(width 0.254)
		(layer "F.Cu")
		(net "GND")
	)
	(segment
		(start 44.754546 -276.366732)
		(end 45.859446 -276.366732)
		(width 0.381)
		(layer "F.Cu")
		(net "GND")
	)
	(segment
		(start 65.047114 -314.616592)
		(end 66.152014 -314.616592)
		(width 0.381)
		(layer "F.Cu")
		(net "GND")
	)
	(segment
		(start 370.967762 -256.639314)
		(end 370.967762 -256.807462)
		(width 0.2032)
		(layer "F.Cu")
		(net "GND")
	)
	(segment
		(start 45.859446 -272.116804)
		(end 46.964346 -272.116804)
		(width 0.381)
		(layer "F.Cu")
		(net "GND")
	)
	(segment
		(start 277.607014 -258.516628)
		(end 278.711914 -258.516628)
		(width 0.381)
		(layer "F.Cu")
		(net "GND")
	)
	(segment
		(start 272.273014 -306.116736)
		(end 271.168114 -306.116736)
		(width 0.381)
		(layer "F.Cu")
		(net "GND")
	)
	(segment
		(start 23.228046 -296.766742)
		(end 24.332946 -296.766742)
		(width 0.381)
		(layer "F.Cu")
		(net "GND")
	)
	(segment
		(start 195.427346 -261.916672)
		(end 196.532246 -261.916672)
		(width 0.381)
		(layer "F.Cu")
		(net "GND")
	)
	(segment
		(start 77.997304 -344.741754)
		(end 78.27645 -344.741754)
		(width 0.1778)
		(layer "F.Cu")
		(net "GND")
	)
	(segment
		(start 289.250882 -219.41663)
		(end 290.355782 -219.41663)
		(width 0.381)
		(layer "F.Cu")
		(net "GND")
	)
	(segment
		(start 260.180582 -272.966688)
		(end 261.285482 -272.966688)
		(width 0.381)
		(layer "F.Cu")
		(net "GND")
	)
	(segment
		(start 115.106704 -360.83875)
		(end 115.716304 -360.83875)
		(width 0.381)
		(layer "F.Cu")
		(net "GND")
	)
	(segment
		(start 459.559914 -236.416596)
		(end 458.455014 -236.416596)
		(width 0.381)
		(layer "F.Cu")
		(net "GND")
	)
	(segment
		(start 125.737112 -226.017582)
		(end 125.737366 -226.017328)
		(width 0.254)
		(layer "F.Cu")
		(net "GND")
	)
	(segment
		(start 86.265766 -237.411768)
		(end 86.265766 -237.947454)
		(width 0.254)
		(layer "F.Cu")
		(net "GND")
	)
	(segment
		(start 342.66378 -223.297496)
		(end 342.66378 -222.76181)
		(width 0.254)
		(layer "F.Cu")
		(net "GND")
	)
	(segment
		(start 411.958282 -226.216718)
		(end 410.853382 -226.216718)
		(width 0.381)
		(layer "F.Cu")
		(net "GND")
	)
	(segment
		(start 271.168114 -227.066602)
		(end 272.273014 -227.066602)
		(width 0.381)
		(layer "F.Cu")
		(net "GND")
	)
	(segment
		(start 350.652334 -230.622602)
		(end 350.65208 -230.622348)
		(width 0.2032)
		(layer "F.Cu")
		(net "GND")
	)
	(segment
		(start 175.005746 -221.96679)
		(end 173.900846 -221.96679)
		(width 0.381)
		(layer "F.Cu")
		(net "GND")
	)
	(segment
		(start 45.859446 -311.216802)
		(end 46.964346 -311.216802)
		(width 0.381)
		(layer "F.Cu")
		(net "GND")
	)
	(segment
		(start 35.976814 -306.96662)
		(end 34.871914 -306.96662)
		(width 0.381)
		(layer "F.Cu")
		(net "GND")
	)
	(segment
		(start 42.415714 -289.966654)
		(end 41.310814 -289.966654)
		(width 0.381)
		(layer "F.Cu")
		(net "GND")
	)
	(segment
		(start 122.558048 -275.35886)
		(end 122.558048 -275.8948)
		(width 0.254)
		(layer "F.Cu")
		(net "GND")
	)
	(segment
		(start 432.379882 -194.766692)
		(end 433.484782 -194.766692)
		(width 0.381)
		(layer "F.Cu")
		(net "GND")
	)
	(segment
		(start 208.176114 -262.76681)
		(end 209.281014 -262.76681)
		(width 0.381)
		(layer "F.Cu")
		(net "GND")
	)
	(segment
		(start 197.98284 -119.344948)
		(end 197.59041 -119.344948)
		(width 0.3556)
		(layer "F.Cu")
		(net "GND")
	)
	(segment
		(start 92.844112 -216.250774)
		(end 92.844366 -216.25052)
		(width 0.254)
		(layer "F.Cu")
		(net "GND")
	)
	(segment
		(start 99.532694 -261.522718)
		(end 99.532694 -262.058404)
		(width 0.254)
		(layer "F.Cu")
		(net "GND")
	)
	(segment
		(start 263.624314 -225.36658)
		(end 264.729214 -225.36658)
		(width 0.381)
		(layer "F.Cu")
		(net "GND")
	)
	(segment
		(start 302.534574 -435.19598)
		(end 302.923702 -435.585108)
		(width 0.3556)
		(layer "F.Cu")
		(net "GND")
	)
	(segment
		(start 30.771846 -281.466798)
		(end 31.876746 -281.466798)
		(width 0.381)
		(layer "F.Cu")
		(net "GND")
	)
	(segment
		(start 383.655062 -259.093462)
		(end 383.654808 -259.616956)
		(width 0.2032)
		(layer "F.Cu")
		(net "GND")
	)
	(segment
		(start 132.895848 -259.093462)
		(end 132.895594 -259.616956)
		(width 0.2032)
		(layer "F.Cu")
		(net "GND")
	)
	(segment
		(start 385.534662 -257.45313)
		(end 385.534662 -257.988816)
		(width 0.254)
		(layer "F.Cu")
		(net "GND")
	)
	(segment
		(start 444.472314 -311.216802)
		(end 445.577214 -311.216802)
		(width 0.381)
		(layer "F.Cu")
		(net "GND")
	)
	(segment
		(start 290.355782 -288.266632)
		(end 291.460682 -288.266632)
		(width 0.381)
		(layer "F.Cu")
		(net "GND")
	)
	(segment
		(start 369.558316 -287.288986)
		(end 369.558062 -287.28924)
		(width 0.254)
		(layer "F.Cu")
		(net "GND")
	)
	(segment
		(start 351.122234 -220.041724)
		(end 351.122234 -219.506038)
		(width 0.254)
		(layer "F.Cu")
		(net "GND")
	)
	(segment
		(start 165.47846 -57.556908)
		(end 166.857934 -57.556908)
		(width 0.3556)
		(layer "F.Cu")
		(net "GND")
	)
	(segment
		(start 33.767014 -245.76659)
		(end 34.871914 -245.76659)
		(width 0.381)
		(layer "F.Cu")
		(net "GND")
	)
	(segment
		(start 396.493746 -61.249814)
		(end 397.765016 -61.249814)
		(width 0.254)
		(layer "F.Cu")
		(net "GND")
	)
	(segment
		(start 215.719914 -301.01667)
		(end 216.824814 -301.01667)
		(width 0.381)
		(layer "F.Cu")
		(net "GND")
	)
	(segment
		(start 93.34246 -338.472272)
		(end 93.195394 -338.619338)
		(width 0.381)
		(layer "F.Cu")
		(net "GND")
	)
	(segment
		(start 65.047114 -299.316648)
		(end 66.152014 -299.316648)
		(width 0.381)
		(layer "F.Cu")
		(net "GND")
	)
	(segment
		(start 345.593162 -282.683966)
		(end 345.593162 -283.219906)
		(width 0.2032)
		(layer "F.Cu")
		(net "GND")
	)
	(segment
		(start 294.904414 -309.51678)
		(end 293.799514 -309.51678)
		(width 0.381)
		(layer "F.Cu")
		(net "GND")
	)
	(segment
		(start 65.047114 -198.166736)
		(end 66.152014 -198.166736)
		(width 0.381)
		(layer "F.Cu")
		(net "GND")
	)
	(segment
		(start 293.799514 -292.516814)
		(end 292.694614 -292.516814)
		(width 0.381)
		(layer "F.Cu")
		(net "GND")
	)
	(segment
		(start 386.474716 -281.869896)
		(end 386.474462 -282.405836)
		(width 0.13208)
		(layer "F.Cu")
		(net "GND")
	)
	(segment
		(start 29.666946 -201.56678)
		(end 30.771846 -201.56678)
		(width 0.381)
		(layer "F.Cu")
		(net "GND")
	)
	(segment
		(start 217.062558 -23.292308)
		(end 217.062558 -25.311354)
		(width 0.3556)
		(layer "F.Cu")
		(net "GND")
	)
	(segment
		(start 123.497848 -257.45313)
		(end 123.497594 -257.98907)
		(width 0.2032)
		(layer "F.Cu")
		(net "GND")
	)
	(segment
		(start 107.521248 -287.288986)
		(end 107.520994 -287.28924)
		(width 0.254)
		(layer "F.Cu")
		(net "GND")
	)
	(segment
		(start 334.205834 -244.458744)
		(end 335.14538 -243.922804)
		(width 0.2032)
		(layer "F.Cu")
		(net "GND")
	)
	(segment
		(start 100.942648 -284.033468)
		(end 100.942394 -284.033722)
		(width 0.254)
		(layer "F.Cu")
		(net "GND")
	)
	(segment
		(start 207.071214 -308.666642)
		(end 208.176114 -308.666642)
		(width 0.381)
		(layer "F.Cu")
		(net "GND")
	)
	(segment
		(start 89.664794 -255.825498)
		(end 89.664794 -256.361438)
		(width 0.2032)
		(layer "F.Cu")
		(net "GND")
	)
	(segment
		(start 28.028646 -387.246876)
		(end 28.638246 -387.246876)
		(width 0.3556)
		(layer "F.Cu")
		(net "GND")
	)
	(segment
		(start 371.437916 -278.614378)
		(end 371.437916 -279.150318)
		(width 0.254)
		(layer "F.Cu")
		(net "GND")
	)
	(segment
		(start 187.462922 -17.655032)
		(end 187.462922 -16.551148)
		(width 0.3556)
		(layer "F.Cu")
		(net "GND")
	)
	(segment
		(start 96.603312 -222.76181)
		(end 96.603566 -222.761556)
		(width 0.254)
		(layer "F.Cu")
		(net "GND")
	)
	(segment
		(start 120.208294 -281.05608)
		(end 120.208548 -281.59202)
		(width 0.2032)
		(layer "F.Cu")
		(net "GND")
	)
	(segment
		(start 138.534648 -275.35886)
		(end 139.004548 -275.080984)
		(width 0.254)
		(layer "F.Cu")
		(net "GND")
	)
	(segment
		(start 301.343314 -238.966756)
		(end 302.448214 -238.966756)
		(width 0.381)
		(layer "F.Cu")
		(net "GND")
	)
	(segment
		(start 436.928514 -273.816572)
		(end 438.033414 -273.816572)
		(width 0.381)
		(layer "F.Cu")
		(net "GND")
	)
	(segment
		(start 117.279166 -229.808532)
		(end 117.279166 -229.272846)
		(width 0.2032)
		(layer "F.Cu")
		(net "GND")
	)
	(segment
		(start 215.719914 -297.616626)
		(end 216.824814 -297.616626)
		(width 0.381)
		(layer "F.Cu")
		(net "GND")
	)
	(segment
		(start 366.15878 -231.436418)
		(end 366.159034 -231.436164)
		(width 0.2032)
		(layer "F.Cu")
		(net "GND")
	)
	(segment
		(start 377.436634 -236.319568)
		(end 377.436634 -235.783882)
		(width 0.2032)
		(layer "F.Cu")
		(net "GND")
	)
	(segment
		(start 107.583986 -408.036014)
		(end 107.3404 -408.2796)
		(width 0.3556)
		(layer "F.Cu")
		(net "GND")
	)
	(segment
		(start 336.49285 -54.089046)
		(end 336.766408 -54.558946)
		(width 0.2032)
		(layer "F.Cu")
		(net "GND")
	)
	(segment
		(start 375.557034 -244.45849)
		(end 375.557034 -243.922804)
		(width 0.2032)
		(layer "F.Cu")
		(net "GND")
	)
	(segment
		(start 453.121014 -301.866808)
		(end 452.016114 -301.866808)
		(width 0.381)
		(layer "F.Cu")
		(net "GND")
	)
	(segment
		(start 173.355762 -108.175552)
		(end 172.955712 -107.775502)
		(width 0.3556)
		(layer "F.Cu")
		(net "GND")
	)
	(segment
		(start 30.771846 -240.666778)
		(end 31.876746 -240.666778)
		(width 0.381)
		(layer "F.Cu")
		(net "GND")
	)
	(segment
		(start 386.474716 -267.219938)
		(end 386.474462 -267.755878)
		(width 0.254)
		(layer "F.Cu")
		(net "GND")
	)
	(segment
		(start 240.51387 -247.415558)
		(end 240.50371 -247.415558)
		(width 0.3556)
		(layer "F.Cu")
		(net "GND")
	)
	(segment
		(start 260.180582 -289.966654)
		(end 259.075682 -289.966654)
		(width 0.381)
		(layer "F.Cu")
		(net "GND")
	)
	(segment
		(start 294.904414 -289.11677)
		(end 293.799514 -289.11677)
		(width 0.381)
		(layer "F.Cu")
		(net "GND")
	)
	(segment
		(start 133.835648 -280.242264)
		(end 133.835394 -280.778204)
		(width 0.254)
		(layer "F.Cu")
		(net "GND")
	)
	(segment
		(start 218.52763 -130.957828)
		(end 218.52763 -130.317748)
		(width 0.3556)
		(layer "F.Cu")
		(net "GND")
	)
	(segment
		(start 344.07348 -228.994716)
		(end 344.07348 -228.45903)
		(width 0.2032)
		(layer "F.Cu")
		(net "GND")
	)
	(segment
		(start 164.018214 -241.516662)
		(end 162.913314 -241.516662)
		(width 0.381)
		(layer "F.Cu")
		(net "GND")
	)
	(segment
		(start 433.484782 -202.416664)
		(end 434.589682 -202.416664)
		(width 0.381)
		(layer "F.Cu")
		(net "GND")
	)
	(segment
		(start 165.252146 -267.016738)
		(end 166.357046 -267.016738)
		(width 0.381)
		(layer "F.Cu")
		(net "GND")
	)
	(segment
		(start 355.82098 -216.78646)
		(end 355.82098 -216.250774)
		(width 0.254)
		(layer "F.Cu")
		(net "GND")
	)
	(segment
		(start 96.243648 -279.150064)
		(end 96.243394 -279.150318)
		(width 0.254)
		(layer "F.Cu")
		(net "GND")
	)
	(segment
		(start 267.724382 -288.266632)
		(end 268.829282 -288.266632)
		(width 0.381)
		(layer "F.Cu")
		(net "GND")
	)
	(segment
		(start 326.999854 -39.445946)
		(end 327.41489 -38.945566)
		(width 0.2032)
		(layer "F.Cu")
		(net "GND")
	)
	(segment
		(start 8.140446 -296.766742)
		(end 9.245346 -296.766742)
		(width 0.381)
		(layer "F.Cu")
		(net "GND")
	)
	(segment
		(start 132.785866 -233.87812)
		(end 132.785866 -233.34218)
		(width 0.2032)
		(layer "F.Cu")
		(net "GND")
	)
	(segment
		(start 459.559914 -221.96679)
		(end 458.455014 -221.96679)
		(width 0.381)
		(layer "F.Cu")
		(net "GND")
	)
	(segment
		(start 103.181912 -220.041978)
		(end 103.182166 -220.041724)
		(width 0.254)
		(layer "F.Cu")
		(net "GND")
	)
	(segment
		(start 372.377716 -273.730974)
		(end 372.377716 -274.26666)
		(width 0.254)
		(layer "F.Cu")
		(net "GND")
	)
	(segment
		(start 309.99684 -20.23364)
		(end 307.27269 -20.23364)
		(width 0.3556)
		(layer "F.Cu")
		(net "GND")
	)
	(segment
		(start 88.309958 -31.120588)
		(end 87.13216 -31.120588)
		(width 0.3556)
		(layer "F.Cu")
		(net "GND")
	)
	(segment
		(start 449.677282 -297.616626)
		(end 448.572382 -297.616626)
		(width 0.381)
		(layer "F.Cu")
		(net "GND")
	)
	(segment
		(start 343.243916 -287.288986)
		(end 343.243662 -287.28924)
		(width 0.254)
		(layer "F.Cu")
		(net "GND")
	)
	(segment
		(start 101.772212 -250.15571)
		(end 101.772212 -249.620024)
		(width 0.2032)
		(layer "F.Cu")
		(net "GND")
	)
	(segment
		(start 435.823614 -234.716574)
		(end 436.928514 -234.716574)
		(width 0.381)
		(layer "F.Cu")
		(net "GND")
	)
	(segment
		(start 212.710268 -68.594732)
		(end 212.44306 -68.86194)
		(width 0.3556)
		(layer "F.Cu")
		(net "GND")
	)
	(segment
		(start 23.669752 -409.402534)
		(end 23.060152 -409.402534)
		(width 0.381)
		(layer "F.Cu")
		(net "GND")
	)
	(segment
		(start 26.223214 -235.566712)
		(end 27.328114 -235.566712)
		(width 0.381)
		(layer "F.Cu")
		(net "GND")
	)
	(segment
		(start 459.559914 -216.016586)
		(end 458.455014 -216.016586)
		(width 0.381)
		(layer "F.Cu")
		(net "GND")
	)
	(segment
		(start 347.36278 -234.69219)
		(end 347.36278 -234.156504)
		(width 0.254)
		(layer "F.Cu")
		(net "GND")
	)
	(segment
		(start 180.339746 -270.416782)
		(end 181.444646 -270.416782)
		(width 0.381)
		(layer "F.Cu")
		(net "GND")
	)
	(segment
		(start 334.205834 -239.57534)
		(end 334.67548 -239.853216)
		(width 0.254)
		(layer "F.Cu")
		(net "GND")
	)
	(segment
		(start 436.928514 -220.266768)
		(end 438.033414 -220.266768)
		(width 0.381)
		(layer "F.Cu")
		(net "GND")
	)
	(segment
		(start 409.748482 -198.166736)
		(end 410.853382 -198.166736)
		(width 0.381)
		(layer "F.Cu")
		(net "GND")
	)
	(segment
		(start 308.887114 -272.116804)
		(end 309.992014 -272.116804)
		(width 0.381)
		(layer "F.Cu")
		(net "GND")
	)
	(segment
		(start 188.988446 -285.716726)
		(end 190.093346 -285.716726)
		(width 0.381)
		(layer "F.Cu")
		(net "GND")
	)
	(segment
		(start 84.812632 -269.938246)
		(end 85.334094 -269.66164)
		(width 0.2032)
		(layer "F.Cu")
		(net "GND")
	)
	(segment
		(start 20.346924 -11.26998)
		(end 20.346924 -12.37488)
		(width 0.3556)
		(layer "F.Cu")
		(net "GND")
	)
	(segment
		(start 100.472494 -289.195002)
		(end 100.472494 -289.807142)
		(width 0.2032)
		(layer "F.Cu")
		(net "GND")
	)
	(segment
		(start 42.415714 -269.566644)
		(end 41.310814 -269.566644)
		(width 0.381)
		(layer "F.Cu")
		(net "GND")
	)
	(segment
		(start 377.43638 -222.76181)
		(end 377.436634 -222.761556)
		(width 0.254)
		(layer "F.Cu")
		(net "GND")
	)
	(segment
		(start 276.373082 -258.516628)
		(end 275.268182 -258.516628)
		(width 0.381)
		(layer "F.Cu")
		(net "GND")
	)
	(segment
		(start 135.135366 -228.180646)
		(end 135.135366 -227.64496)
		(width 0.2032)
		(layer "F.Cu")
		(net "GND")
	)
	(segment
		(start 416.556952 -11.26998)
		(end 416.556952 -12.37488)
		(width 0.3556)
		(layer "F.Cu")
		(net "GND")
	)
	(segment
		(start 101.302312 -220.041978)
		(end 101.302566 -220.041724)
		(width 0.254)
		(layer "F.Cu")
		(net "GND")
	)
	(segment
		(start 37.330634 -111.603282)
		(end 37.940234 -111.603282)
		(width 0.3556)
		(layer "F.Cu")
		(net "GND")
	)
	(segment
		(start 26.223214 -272.966688)
		(end 27.328114 -272.966688)
		(width 0.381)
		(layer "F.Cu")
		(net "GND")
	)
	(segment
		(start 44.754546 -268.71676)
		(end 45.859446 -268.71676)
		(width 0.381)
		(layer "F.Cu")
		(net "GND")
	)
	(segment
		(start 9.963404 -100.417884)
		(end 9.92886 -100.452428)
		(width 0.3556)
		(layer "F.Cu")
		(net "GND")
	)
	(segment
		(start 433.484782 -198.166736)
		(end 434.589682 -198.166736)
		(width 0.381)
		(layer "F.Cu")
		(net "GND")
	)
	(segment
		(start 433.484782 -275.516594)
		(end 434.589682 -275.516594)
		(width 0.381)
		(layer "F.Cu")
		(net "GND")
	)
	(segment
		(start 190.093346 -263.616694)
		(end 188.988446 -263.616694)
		(width 0.381)
		(layer "F.Cu")
		(net "GND")
	)
	(segment
		(start 134.195566 -245.55069)
		(end 134.195566 -246.08663)
		(width 0.2032)
		(layer "F.Cu")
		(net "GND")
	)
	(segment
		(start 12.240514 -249.166634)
		(end 13.345414 -249.166634)
		(width 0.381)
		(layer "F.Cu")
		(net "GND")
	)
	(segment
		(start 261.285482 -258.516628)
		(end 260.180582 -258.516628)
		(width 0.381)
		(layer "F.Cu")
		(net "GND")
	)
	(segment
		(start 282.811982 -215.166702)
		(end 283.916882 -215.166702)
		(width 0.381)
		(layer "F.Cu")
		(net "GND")
	)
	(segment
		(start 277.607014 -279.766776)
		(end 278.711914 -279.766776)
		(width 0.381)
		(layer "F.Cu")
		(net "GND")
	)
	(segment
		(start 346.995496 -25.788366)
		(end 346.964254 -25.757124)
		(width 0.381)
		(layer "F.Cu")
		(net "GND")
	)
	(segment
		(start 456.116182 -291.666676)
		(end 455.011282 -291.666676)
		(width 0.381)
		(layer "F.Cu")
		(net "GND")
	)
	(segment
		(start 380.835916 -275.35886)
		(end 380.835662 -275.8948)
		(width 0.2032)
		(layer "F.Cu")
		(net "GND")
	)
	(segment
		(start 188.988446 -234.716574)
		(end 187.883546 -234.716574)
		(width 0.381)
		(layer "F.Cu")
		(net "GND")
	)
	(segment
		(start 102.242112 -220.041978)
		(end 102.242366 -220.041724)
		(width 0.254)
		(layer "F.Cu")
		(net "GND")
	)
	(segment
		(start 208.176114 -264.466578)
		(end 209.281014 -264.466578)
		(width 0.381)
		(layer "F.Cu")
		(net "GND")
	)
	(segment
		(start 98.013012 -242.016788)
		(end 98.013012 -241.481102)
		(width 0.2032)
		(layer "F.Cu")
		(net "GND")
	)
	(segment
		(start 343.60358 -223.297496)
		(end 343.60358 -222.76181)
		(width 0.254)
		(layer "F.Cu")
		(net "GND")
	)
	(segment
		(start 104.121712 -222.76181)
		(end 104.121966 -222.761556)
		(width 0.254)
		(layer "F.Cu")
		(net "GND")
	)
	(segment
		(start 127.257048 -278.614378)
		(end 127.257048 -279.150064)
		(width 0.254)
		(layer "F.Cu")
		(net "GND")
	)
	(segment
		(start 383.914904 -73.920858)
		(end 383.952496 -73.95845)
		(width 0.3556)
		(layer "F.Cu")
		(net "GND")
	)
	(segment
		(start 340.78418 -229.808786)
		(end 340.784434 -229.808532)
		(width 0.2032)
		(layer "F.Cu")
		(net "GND")
	)
	(segment
		(start 115.106704 -359.94975)
		(end 115.716304 -359.94975)
		(width 0.381)
		(layer "F.Cu")
		(net "GND")
	)
	(segment
		(start 342.243918 -334.191102)
		(end 341.815928 -333.763112)
		(width 0.2032)
		(layer "F.Cu")
		(net "GND")
	)
	(segment
		(start 94.833694 -276.708362)
		(end 94.833948 -276.708616)
		(width 0.2032)
		(layer "F.Cu")
		(net "GND")
	)
	(segment
		(start 127.726694 -277.800562)
		(end 127.726948 -278.336502)
		(width 0.2032)
		(layer "F.Cu")
		(net "GND")
	)
	(segment
		(start 334.785716 -278.614378)
		(end 334.315562 -278.336502)
		(width 0.254)
		(layer "F.Cu")
		(net "GND")
	)
	(segment
		(start 12.240514 -261.066788)
		(end 13.345414 -261.066788)
		(width 0.381)
		(layer "F.Cu")
		(net "GND")
	)
	(segment
		(start 263.624314 -261.916672)
		(end 264.729214 -261.916672)
		(width 0.381)
		(layer "F.Cu")
		(net "GND")
	)
	(segment
		(start 138.894312 -229.808786)
		(end 139.364466 -230.086662)
		(width 0.254)
		(layer "F.Cu")
		(net "GND")
	)
	(segment
		(start 354.051362 -274.54479)
		(end 354.051362 -275.08073)
		(width 0.254)
		(layer "F.Cu")
		(net "GND")
	)
	(segment
		(start 439.923682 -262.76681)
		(end 441.028582 -262.76681)
		(width 0.381)
		(layer "F.Cu")
		(net "GND")
	)
	(segment
		(start 276.373082 -250.866656)
		(end 275.268182 -250.866656)
		(width 0.381)
		(layer "F.Cu")
		(net "GND")
	)
	(segment
		(start 133.255512 -247.714262)
		(end 133.255512 -247.178322)
		(width 0.2032)
		(layer "F.Cu")
		(net "GND")
	)
	(segment
		(start 336.55508 -245.272306)
		(end 336.55508 -244.73662)
		(width 0.2032)
		(layer "F.Cu")
		(net "GND")
	)
	(segment
		(start 113.989866 -238.761524)
		(end 113.989866 -238.225838)
		(width 0.254)
		(layer "F.Cu")
		(net "GND")
	)
	(segment
		(start 383.07518 -226.553268)
		(end 383.07518 -226.017582)
		(width 0.254)
		(layer "F.Cu")
		(net "GND")
	)
	(segment
		(start 267.724382 -226.216718)
		(end 268.829282 -226.216718)
		(width 0.381)
		(layer "F.Cu")
		(net "GND")
	)
	(segment
		(start 335.14538 -216.250774)
		(end 335.145126 -216.25052)
		(width 0.2032)
		(layer "F.Cu")
		(net "GND")
	)
	(segment
		(start 126.207266 -242.017042)
		(end 126.207012 -242.016788)
		(width 0.2032)
		(layer "F.Cu")
		(net "GND")
	)
	(segment
		(start 215.719914 -284.866588)
		(end 216.824814 -284.866588)
		(width 0.381)
		(layer "F.Cu")
		(net "GND")
	)
	(segment
		(start 196.532246 -272.116804)
		(end 195.427346 -272.116804)
		(width 0.381)
		(layer "F.Cu")
		(net "GND")
	)
	(segment
		(start 200.632314 -238.116618)
		(end 201.737214 -238.116618)
		(width 0.381)
		(layer "F.Cu")
		(net "GND")
	)
	(segment
		(start 56.867044 -12.37488)
		(end 56.867044 -11.26998)
		(width 0.3556)
		(layer "F.Cu")
		(net "GND")
	)
	(segment
		(start 441.028582 -200.716642)
		(end 442.133482 -200.716642)
		(width 0.381)
		(layer "F.Cu")
		(net "GND")
	)
	(segment
		(start 439.923682 -221.116652)
		(end 441.028582 -221.116652)
		(width 0.381)
		(layer "F.Cu")
		(net "GND")
	)
	(segment
		(start 344.073734 -232.250488)
		(end 344.07348 -232.250234)
		(width 0.2032)
		(layer "F.Cu")
		(net "GND")
	)
	(segment
		(start 462.555082 -194.766692)
		(end 463.659982 -194.766692)
		(width 0.381)
		(layer "F.Cu")
		(net "GND")
	)
	(segment
		(start 439.923682 -308.666642)
		(end 441.028582 -308.666642)
		(width 0.381)
		(layer "F.Cu")
		(net "GND")
	)
	(segment
		(start 379.896116 -284.033468)
		(end 379.895862 -284.033722)
		(width 0.254)
		(layer "F.Cu")
		(net "GND")
	)
	(segment
		(start 339.954362 -282.683966)
		(end 339.954362 -283.219906)
		(width 0.254)
		(layer "F.Cu")
		(net "GND")
	)
	(segment
		(start 48.638714 -235.566712)
		(end 49.959514 -235.566712)
		(width 0.381)
		(layer "F.Cu")
		(net "GND")
	)
	(segment
		(start 94.597728 -335.541112)
		(end 94.318582 -335.541112)
		(width 0.1778)
		(layer "F.Cu")
		(net "GND")
	)
	(segment
		(start 96.603312 -220.041978)
		(end 96.603566 -220.041724)
		(width 0.254)
		(layer "F.Cu")
		(net "GND")
	)
	(segment
		(start 376.49658 -216.250774)
		(end 376.496834 -216.25052)
		(width 0.254)
		(layer "F.Cu")
		(net "GND")
	)
	(segment
		(start 93.783912 -228.1809)
		(end 93.784166 -228.180646)
		(width 0.2032)
		(layer "F.Cu")
		(net "GND")
	)
	(segment
		(start 358.280716 -275.894546)
		(end 358.280462 -275.8948)
		(width 0.254)
		(layer "F.Cu")
		(net "GND")
	)
	(segment
		(start 95.663512 -216.78646)
		(end 95.663512 -216.250774)
		(width 0.254)
		(layer "F.Cu")
		(net "GND")
	)
	(segment
		(start 456.116182 -239.81664)
		(end 455.011282 -239.81664)
		(width 0.381)
		(layer "F.Cu")
		(net "GND")
	)
	(segment
		(start 414.297114 -204.96657)
		(end 415.402014 -204.96657)
		(width 0.381)
		(layer "F.Cu")
		(net "GND")
	)
	(segment
		(start 348.30258 -222.76181)
		(end 348.302834 -222.761556)
		(width 0.254)
		(layer "F.Cu")
		(net "GND")
	)
	(segment
		(start 187.883546 -304.416714)
		(end 188.988446 -304.416714)
		(width 0.381)
		(layer "F.Cu")
		(net "GND")
	)
	(segment
		(start 49.959514 -286.56661)
		(end 51.064414 -286.56661)
		(width 0.381)
		(layer "F.Cu")
		(net "GND")
	)
	(segment
		(start 169.141648 -312.91657)
		(end 170.457114 -312.91657)
		(width 0.381)
		(layer "F.Cu")
		(net "GND")
	)
	(segment
		(start 345.554554 -52.952396)
		(end 346.384626 -52.952396)
		(width 0.2032)
		(layer "F.Cu")
		(net "GND")
	)
	(segment
		(start 277.607014 -246.616728)
		(end 278.711914 -246.616728)
		(width 0.381)
		(layer "F.Cu")
		(net "GND")
	)
	(segment
		(start 334.205834 -218.414346)
		(end 334.205834 -217.87866)
		(width 0.2032)
		(layer "F.Cu")
		(net "GND")
	)
	(segment
		(start 116.339112 -226.017582)
		(end 116.339366 -226.017328)
		(width 0.254)
		(layer "F.Cu")
		(net "GND")
	)
	(segment
		(start 342.66378 -249.342148)
		(end 342.66378 -248.806208)
		(width 0.2032)
		(layer "F.Cu")
		(net "GND")
	)
	(segment
		(start 52.500276 -144.744186)
		(end 52.72913 -144.744186)
		(width 0.2032)
		(layer "F.Cu")
		(net "GND")
	)
	(segment
		(start 458.455014 -300.166786)
		(end 459.559914 -300.166786)
		(width 0.381)
		(layer "F.Cu")
		(net "GND")
	)
	(segment
		(start 99.063048 -286.7533)
		(end 99.063048 -287.288986)
		(width 0.254)
		(layer "F.Cu")
		(net "GND")
	)
	(segment
		(start 448.572382 -244.066568)
		(end 447.467482 -244.066568)
		(width 0.381)
		(layer "F.Cu")
		(net "GND")
	)
	(segment
		(start 99.063048 -281.869896)
		(end 99.062794 -282.405836)
		(width 0.2032)
		(layer "F.Cu")
		(net "GND")
	)
	(segment
		(start 13.345414 -316.316614)
		(end 12.240514 -316.316614)
		(width 0.381)
		(layer "F.Cu")
		(net "GND")
	)
	(segment
		(start 99.422966 -231.436164)
		(end 99.422966 -230.900478)
		(width 0.2032)
		(layer "F.Cu")
		(net "GND")
	)
	(segment
		(start 338.120736 -56.908446)
		(end 337.581494 -56.908446)
		(width 0.2032)
		(layer "F.Cu")
		(net "GND")
	)
	(segment
		(start 199.527414 -222.816674)
		(end 200.632314 -222.816674)
		(width 0.381)
		(layer "F.Cu")
		(net "GND")
	)
	(segment
		(start 293.799514 -296.766742)
		(end 292.694614 -296.766742)
		(width 0.381)
		(layer "F.Cu")
		(net "GND")
	)
	(segment
		(start 296.794682 -250.866656)
		(end 297.899582 -250.866656)
		(width 0.381)
		(layer "F.Cu")
		(net "GND")
	)
	(segment
		(start 424.836082 -232.166668)
		(end 425.940982 -232.166668)
		(width 0.381)
		(layer "F.Cu")
		(net "GND")
	)
	(segment
		(start 117.89664 -403.245828)
		(end 118.44528 -403.794468)
		(width 0.3556)
		(layer "F.Cu")
		(net "GND")
	)
	(segment
		(start 98.123248 -275.894546)
		(end 98.122994 -275.8948)
		(width 0.2032)
		(layer "F.Cu")
		(net "GND")
	)
	(segment
		(start 413.43326 -362.562648)
		(end 413.038798 -362.168186)
		(width 0.2032)
		(layer "F.Cu")
		(net "GND")
	)
	(segment
		(start 347.36278 -241.203226)
		(end 347.363034 -241.202972)
		(width 0.2032)
		(layer "F.Cu")
		(net "GND")
	)
	(segment
		(start 267.724382 -308.666642)
		(end 268.829282 -308.666642)
		(width 0.381)
		(layer "F.Cu")
		(net "GND")
	)
	(segment
		(start 22.123146 -197.316598)
		(end 23.228046 -197.316598)
		(width 0.381)
		(layer "F.Cu")
		(net "GND")
	)
	(segment
		(start 373.787162 -258.802886)
		(end 373.787416 -258.80314)
		(width 0.2032)
		(layer "F.Cu")
		(net "GND")
	)
	(segment
		(start 39.420546 -309.51678)
		(end 38.315646 -309.51678)
		(width 0.381)
		(layer "F.Cu")
		(net "GND")
	)
	(segment
		(start 420.736014 -221.96679)
		(end 421.840914 -221.96679)
		(width 0.381)
		(layer "F.Cu")
		(net "GND")
	)
	(segment
		(start 118.218712 -226.553268)
		(end 118.218712 -226.017582)
		(width 0.254)
		(layer "F.Cu")
		(net "GND")
	)
	(segment
		(start 428.279814 -261.916672)
		(end 429.384714 -261.916672)
		(width 0.381)
		(layer "F.Cu")
		(net "GND")
	)
	(segment
		(start 372.847362 -281.591512)
		(end 372.847616 -281.591766)
		(width 0.254)
		(layer "F.Cu")
		(net "GND")
	)
	(segment
		(start 130.436112 -223.297496)
		(end 130.436112 -222.76181)
		(width 0.254)
		(layer "F.Cu")
		(net "GND")
	)
	(segment
		(start 124.327666 -245.27256)
		(end 124.327412 -245.272306)
		(width 0.2032)
		(layer "F.Cu")
		(net "GND")
	)
	(segment
		(start 199.527414 -269.566644)
		(end 200.632314 -269.566644)
		(width 0.381)
		(layer "F.Cu")
		(net "GND")
	)
	(segment
		(start 286.255714 -225.36658)
		(end 287.360614 -225.36658)
		(width 0.381)
		(layer "F.Cu")
		(net "GND")
	)
	(segment
		(start 214.615014 -295.916604)
		(end 215.719914 -295.916604)
		(width 0.381)
		(layer "F.Cu")
		(net "GND")
	)
	(segment
		(start 289.250882 -277.216616)
		(end 290.355782 -277.216616)
		(width 0.381)
		(layer "F.Cu")
		(net "GND")
	)
	(segment
		(start 301.343314 -227.066602)
		(end 302.448214 -227.066602)
		(width 0.381)
		(layer "F.Cu")
		(net "GND")
	)
	(segment
		(start 125.847094 -266.405868)
		(end 125.847094 -266.941808)
		(width 0.2032)
		(layer "F.Cu")
		(net "GND")
	)
	(segment
		(start 345.416124 -54.747668)
		(end 345.51874 -54.900068)
		(width 0.1778)
		(layer "F.Cu")
		(net "GND")
	)
	(segment
		(start 304.338482 -211.766658)
		(end 305.443382 -211.766658)
		(width 0.381)
		(layer "F.Cu")
		(net "GND")
	)
	(segment
		(start 332.906116 -255.825498)
		(end 332.435962 -255.547622)
		(width 0.254)
		(layer "F.Cu")
		(net "GND")
	)
	(segment
		(start 350.000316 -336.115406)
		(end 349.523304 -336.592418)
		(width 0.2032)
		(layer "F.Cu")
		(net "GND")
	)
	(segment
		(start 370.388134 -228.99497)
		(end 370.38788 -228.994716)
		(width 0.254)
		(layer "F.Cu")
		(net "GND")
	)
	(segment
		(start 166.357046 -204.96657)
		(end 167.461946 -204.96657)
		(width 0.381)
		(layer "F.Cu")
		(net "GND")
	)
	(segment
		(start 342.304116 -255.825498)
		(end 342.304116 -256.361438)
		(width 0.2032)
		(layer "F.Cu")
		(net "GND")
	)
	(segment
		(start 329.439778 -40.931846)
		(end 329.165966 -41.401746)
		(width 0.2032)
		(layer "F.Cu")
		(net "GND")
	)
	(segment
		(start 384.16484 -288.063432)
		(end 384.125216 -288.103056)
		(width 0.254)
		(layer "F.Cu")
		(net "GND")
	)
	(segment
		(start 406.753314 -279.766776)
		(end 405.648414 -279.766776)
		(width 0.381)
		(layer "F.Cu")
		(net "GND")
	)
	(segment
		(start 185.544714 -235.566712)
		(end 186.649614 -235.566712)
		(width 0.381)
		(layer "F.Cu")
		(net "GND")
	)
	(segment
		(start 420.736014 -231.316784)
		(end 421.840914 -231.316784)
		(width 0.381)
		(layer "F.Cu")
		(net "GND")
	)
	(segment
		(start 127.726694 -276.172676)
		(end 127.726948 -276.708616)
		(width 0.2032)
		(layer "F.Cu")
		(net "GND")
	)
	(segment
		(start 215.719914 -202.416664)
		(end 216.824814 -202.416664)
		(width 0.381)
		(layer "F.Cu")
		(net "GND")
	)
	(segment
		(start 87.671656 -79.078836)
		(end 87.671656 -79.815436)
		(width 0.3556)
		(layer "F.Cu")
		(net "GND")
	)
	(segment
		(start 113.629694 -261.522718)
		(end 113.629948 -261.522972)
		(width 0.254)
		(layer "F.Cu")
		(net "GND")
	)
	(segment
		(start 132.785866 -228.45903)
		(end 132.785866 -228.99497)
		(width 0.2032)
		(layer "F.Cu")
		(net "GND")
	)
	(segment
		(start 407.858214 -240.666778)
		(end 406.753314 -240.666778)
		(width 0.381)
		(layer "F.Cu")
		(net "GND")
	)
	(segment
		(start 115.039648 -278.614378)
		(end 115.039648 -279.150064)
		(width 0.254)
		(layer "F.Cu")
		(net "GND")
	)
	(segment
		(start 113.629694 -284.311598)
		(end 113.629694 -284.847538)
		(width 0.254)
		(layer "F.Cu")
		(net "GND")
	)
	(segment
		(start 134.305294 -277.800562)
		(end 134.305294 -278.336502)
		(width 0.2032)
		(layer "F.Cu")
		(net "GND")
	)
	(segment
		(start 443.367414 -317.166752)
		(end 444.472314 -317.166752)
		(width 0.381)
		(layer "F.Cu")
		(net "GND")
	)
	(segment
		(start 46.48581 -394.43025)
		(end 47.21733 -394.43025)
		(width 0.4572)
		(layer "F.Cu")
		(net "GND")
	)
	(segment
		(start 276.373082 -286.56661)
		(end 275.268182 -286.56661)
		(width 0.381)
		(layer "F.Cu")
		(net "GND")
	)
	(segment
		(start 186.649614 -205.816708)
		(end 185.544714 -205.816708)
		(width 0.381)
		(layer "F.Cu")
		(net "GND")
	)
	(segment
		(start 139.706096 -100.729542)
		(end 139.706096 -101.859842)
		(width 0.3556)
		(layer "F.Cu")
		(net "GND")
	)
	(segment
		(start 297.899582 -204.116686)
		(end 299.004482 -204.116686)
		(width 0.381)
		(layer "F.Cu")
		(net "GND")
	)
	(segment
		(start 196.532246 -225.36658)
		(end 197.637146 -225.36658)
		(width 0.381)
		(layer "F.Cu")
		(net "GND")
	)
	(segment
		(start 18.679414 -297.616626)
		(end 19.784314 -297.616626)
		(width 0.381)
		(layer "F.Cu")
		(net "GND")
	)
	(segment
		(start 338.499958 -49.250346)
		(end 338.099908 -49.650396)
		(width 0.2032)
		(layer "F.Cu")
		(net "GND")
	)
	(segment
		(start 196.532246 -236.416596)
		(end 197.637146 -236.416596)
		(width 0.381)
		(layer "F.Cu")
		(net "GND")
	)
	(segment
		(start 427.490128 -343.077038)
		(end 427.490128 -344.017346)
		(width 0.508)
		(layer "F.Cu")
		(net "GND")
	)
	(segment
		(start 376.966734 -214.344758)
		(end 376.966734 -213.732618)
		(width 0.254)
		(layer "F.Cu")
		(net "GND")
	)
	(segment
		(start 354.88118 -223.297496)
		(end 354.88118 -222.76181)
		(width 0.254)
		(layer "F.Cu")
		(net "GND")
	)
	(segment
		(start 378.956316 -254.733298)
		(end 378.956062 -254.733552)
		(width 0.254)
		(layer "F.Cu")
		(net "GND")
	)
	(segment
		(start 195.427346 -270.416782)
		(end 196.532246 -270.416782)
		(width 0.381)
		(layer "F.Cu")
		(net "GND")
	)
	(segment
		(start 44.754546 -301.866808)
		(end 45.859446 -301.866808)
		(width 0.381)
		(layer "F.Cu")
		(net "GND")
	)
	(segment
		(start 204.076046 -301.866808)
		(end 205.180946 -301.866808)
		(width 0.381)
		(layer "F.Cu")
		(net "GND")
	)
	(segment
		(start 178.95951 -355.379274)
		(end 179.31257 -355.379274)
		(width 0.2032)
		(layer "F.Cu")
		(net "GND")
	)
	(segment
		(start 88.255094 -281.05608)
		(end 88.255094 -281.59202)
		(width 0.254)
		(layer "F.Cu")
		(net "GND")
	)
	(segment
		(start 256.080514 -234.716574)
		(end 257.185414 -234.716574)
		(width 0.381)
		(layer "F.Cu")
		(net "GND")
	)
	(segment
		(start 445.577214 -216.016586)
		(end 444.472314 -216.016586)
		(width 0.381)
		(layer "F.Cu")
		(net "GND")
	)
	(segment
		(start 428.279814 -292.516814)
		(end 429.384714 -292.516814)
		(width 0.381)
		(layer "F.Cu")
		(net "GND")
	)
	(segment
		(start 412.956756 -8.320024)
		(end 412.956756 -9.424924)
		(width 0.3556)
		(layer "F.Cu")
		(net "GND")
	)
	(segment
		(start 92.954094 -269.66164)
		(end 92.954348 -269.661894)
		(width 0.2032)
		(layer "F.Cu")
		(net "GND")
	)
	(segment
		(start 134.409942 -104.072182)
		(end 134.409942 -104.62387)
		(width 0.254)
		(layer "F.Cu")
		(net "GND")
	)
	(segment
		(start 418.397182 -232.166668)
		(end 417.292282 -232.166668)
		(width 0.381)
		(layer "F.Cu")
		(net "GND")
	)
	(segment
		(start 358.280716 -275.35886)
		(end 358.280716 -275.894546)
		(width 0.254)
		(layer "F.Cu")
		(net "GND")
	)
	(segment
		(start 424.836082 -213.46668)
		(end 425.940982 -213.46668)
		(width 0.381)
		(layer "F.Cu")
		(net "GND")
	)
	(segment
		(start 41.324022 -358.564942)
		(end 41.197022 -358.691942)
		(width 0.381)
		(layer "F.Cu")
		(net "GND")
	)
	(segment
		(start 340.784434 -236.319568)
		(end 340.784434 -235.783882)
		(width 0.2032)
		(layer "F.Cu")
		(net "GND")
	)
	(segment
		(start 86.265766 -232.528364)
		(end 86.265766 -233.064304)
		(width 0.2032)
		(layer "F.Cu")
		(net "GND")
	)
	(segment
		(start 208.176114 -239.81664)
		(end 209.281014 -239.81664)
		(width 0.381)
		(layer "F.Cu")
		(net "GND")
	)
	(segment
		(start 444.472314 -242.3668)
		(end 445.577214 -242.3668)
		(width 0.381)
		(layer "F.Cu")
		(net "GND")
	)
	(segment
		(start 8.140446 -229.616762)
		(end 9.245346 -229.616762)
		(width 0.381)
		(layer "F.Cu")
		(net "GND")
	)
	(segment
		(start 137.484866 -238.761524)
		(end 136.545066 -238.225584)
		(width 0.254)
		(layer "F.Cu")
		(net "GND")
	)
	(segment
		(start 34.871914 -294.216582)
		(end 33.767014 -294.216582)
		(width 0.381)
		(layer "F.Cu")
		(net "GND")
	)
	(segment
		(start 90.964512 -246.08663)
		(end 90.964512 -245.55069)
		(width 0.2032)
		(layer "F.Cu")
		(net "GND")
	)
	(segment
		(start 413.192214 -246.616728)
		(end 414.297114 -246.616728)
		(width 0.381)
		(layer "F.Cu")
		(net "GND")
	)
	(segment
		(start 187.883546 -279.766776)
		(end 188.988446 -279.766776)
		(width 0.381)
		(layer "F.Cu")
		(net "GND")
	)
	(segment
		(start 374.257316 -268.84757)
		(end 374.257062 -269.38351)
		(width 0.2032)
		(layer "F.Cu")
		(net "GND")
	)
	(segment
		(start 347.345 -38.2905)
		(end 347.214698 -38.2905)
		(width 0.2032)
		(layer "F.Cu")
		(net "GND")
	)
	(segment
		(start 456.116182 -288.266632)
		(end 457.221082 -288.266632)
		(width 0.381)
		(layer "F.Cu")
		(net "GND")
	)
	(segment
		(start 159.918146 -208.366614)
		(end 158.813246 -208.366614)
		(width 0.381)
		(layer "F.Cu")
		(net "GND")
	)
	(segment
		(start 353.581716 -270.475456)
		(end 353.581462 -270.47571)
		(width 0.254)
		(layer "F.Cu")
		(net "GND")
	)
	(segment
		(start 122.448066 -240.389156)
		(end 122.448066 -239.853216)
		(width 0.254)
		(layer "F.Cu")
		(net "GND")
	)
	(segment
		(start 175.755554 -112.175544)
		(end 175.355504 -111.775494)
		(width 0.3556)
		(layer "F.Cu")
		(net "GND")
	)
	(segment
		(start 377.906534 -245.27256)
		(end 377.90628 -245.272306)
		(width 0.2032)
		(layer "F.Cu")
		(net "GND")
	)
	(segment
		(start 166.846758 -129.986278)
		(end 166.846758 -130.737864)
		(width 0.3556)
		(layer "F.Cu")
		(net "GND")
	)
	(segment
		(start 272.273014 -250.016772)
		(end 271.168114 -250.016772)
		(width 0.381)
		(layer "F.Cu")
		(net "GND")
	)
	(segment
		(start 262.519414 -204.96657)
		(end 263.624314 -204.96657)
		(width 0.381)
		(layer "F.Cu")
		(net "GND")
	)
	(segment
		(start 107.3404 -408.2796)
		(end 107.3404 -408.8892)
		(width 0.3556)
		(layer "F.Cu")
		(net "GND")
	)
	(segment
		(start 261.285482 -301.01667)
		(end 260.180582 -301.01667)
		(width 0.381)
		(layer "F.Cu")
		(net "GND")
	)
	(segment
		(start 165.252146 -216.016586)
		(end 166.357046 -216.016586)
		(width 0.381)
		(layer "F.Cu")
		(net "GND")
	)
	(segment
		(start 60.947046 -246.616728)
		(end 62.051946 -246.616728)
		(width 0.381)
		(layer "F.Cu")
		(net "GND")
	)
	(segment
		(start 294.904414 -231.316784)
		(end 293.799514 -231.316784)
		(width 0.381)
		(layer "F.Cu")
		(net "GND")
	)
	(segment
		(start 454.662794 -383.901442)
		(end 455.33183 -383.901442)
		(width 0.381)
		(layer "F.Cu")
		(net "GND")
	)
	(segment
		(start 311.882282 -213.46668)
		(end 312.987182 -213.46668)
		(width 0.381)
		(layer "F.Cu")
		(net "GND")
	)
	(segment
		(start 179.105814 -264.466578)
		(end 178.000914 -264.466578)
		(width 0.381)
		(layer "F.Cu")
		(net "GND")
	)
	(segment
		(start 432.379882 -205.816708)
		(end 433.484782 -205.816708)
		(width 0.381)
		(layer "F.Cu")
		(net "GND")
	)
	(segment
		(start 340.894162 -276.708362)
		(end 340.894416 -276.708616)
		(width 0.2032)
		(layer "F.Cu")
		(net "GND")
	)
	(segment
		(start 429.384714 -287.416748)
		(end 430.489614 -287.416748)
		(width 0.381)
		(layer "F.Cu")
		(net "GND")
	)
	(segment
		(start 127.616966 -244.45849)
		(end 127.616966 -243.922804)
		(width 0.2032)
		(layer "F.Cu")
		(net "GND")
	)
	(segment
		(start 173.900846 -220.266768)
		(end 172.795946 -220.266768)
		(width 0.381)
		(layer "F.Cu")
		(net "GND")
	)
	(segment
		(start 276.373082 -244.066568)
		(end 275.268182 -244.066568)
		(width 0.381)
		(layer "F.Cu")
		(net "GND")
	)
	(segment
		(start 194.193414 -210.066636)
		(end 193.088514 -210.066636)
		(width 0.381)
		(layer "F.Cu")
		(net "GND")
	)
	(segment
		(start 336.899758 -59.265312)
		(end 336.899758 -58.43524)
		(width 0.2032)
		(layer "F.Cu")
		(net "GND")
	)
	(segment
		(start 290.355782 -228.766624)
		(end 289.250882 -228.766624)
		(width 0.381)
		(layer "F.Cu")
		(net "GND")
	)
	(segment
		(start 214.615014 -235.566712)
		(end 215.719914 -235.566712)
		(width 0.381)
		(layer "F.Cu")
		(net "GND")
	)
	(segment
		(start 98.592894 -281.05608)
		(end 98.592894 -281.591766)
		(width 0.254)
		(layer "F.Cu")
		(net "GND")
	)
	(segment
		(start 305.443382 -244.066568)
		(end 306.548282 -244.066568)
		(width 0.381)
		(layer "F.Cu")
		(net "GND")
	)
	(segment
		(start 60.947046 -221.96679)
		(end 62.051946 -221.96679)
		(width 0.381)
		(layer "F.Cu")
		(net "GND")
	)
	(segment
		(start 38.45687 -8.320024)
		(end 38.45687 -9.424924)
		(width 0.3556)
		(layer "F.Cu")
		(net "GND")
	)
	(segment
		(start 48.853344 -354.022914)
		(end 48.526192 -354.022914)
		(width 0.2032)
		(layer "F.Cu")
		(net "GND")
	)
	(segment
		(start 30.771846 -214.316564)
		(end 31.876746 -214.316564)
		(width 0.381)
		(layer "F.Cu")
		(net "GND")
	)
	(segment
		(start 369.558316 -286.7533)
		(end 369.558316 -287.288986)
		(width 0.254)
		(layer "F.Cu")
		(net "GND")
	)
	(segment
		(start 366.738916 -284.033468)
		(end 366.738662 -284.033722)
		(width 0.254)
		(layer "F.Cu")
		(net "GND")
	)
	(segment
		(start 370.858034 -236.319568)
		(end 370.858034 -235.783882)
		(width 0.2032)
		(layer "F.Cu")
		(net "GND")
	)
	(segment
		(start 8.140446 -309.51678)
		(end 9.245346 -309.51678)
		(width 0.381)
		(layer "F.Cu")
		(net "GND")
	)
	(segment
		(start 338.90458 -220.041978)
		(end 338.904834 -220.041724)
		(width 0.254)
		(layer "F.Cu")
		(net "GND")
	)
	(segment
		(start 196.532246 -217.716608)
		(end 197.637146 -217.716608)
		(width 0.381)
		(layer "F.Cu")
		(net "GND")
	)
	(segment
		(start 107.990894 -276.708362)
		(end 107.991148 -276.708616)
		(width 0.2032)
		(layer "F.Cu")
		(net "GND")
	)
	(segment
		(start 101.772212 -243.644674)
		(end 101.772212 -243.108988)
		(width 0.254)
		(layer "F.Cu")
		(net "GND")
	)
	(segment
		(start 353.00158 -226.017582)
		(end 353.001834 -226.017328)
		(width 0.254)
		(layer "F.Cu")
		(net "GND")
	)
	(segment
		(start 124.437648 -280.242264)
		(end 124.437394 -280.778204)
		(width 0.254)
		(layer "F.Cu")
		(net "GND")
	)
	(segment
		(start 281.707082 -249.166634)
		(end 282.811982 -249.166634)
		(width 0.381)
		(layer "F.Cu")
		(net "GND")
	)
	(segment
		(start 414.297114 -201.56678)
		(end 415.402014 -201.56678)
		(width 0.381)
		(layer "F.Cu")
		(net "GND")
	)
	(segment
		(start 105.641648 -283.497782)
		(end 105.641648 -284.033468)
		(width 0.254)
		(layer "F.Cu")
		(net "GND")
	)
	(segment
		(start 343.133934 -230.622602)
		(end 343.13368 -230.622348)
		(width 0.2032)
		(layer "F.Cu")
		(net "GND")
	)
	(segment
		(start 8.140446 -216.016586)
		(end 9.245346 -216.016586)
		(width 0.381)
		(layer "F.Cu")
		(net "GND")
	)
	(segment
		(start 29.666946 -258.516628)
		(end 30.771846 -258.516628)
		(width 0.381)
		(layer "F.Cu")
		(net "GND")
	)
	(segment
		(start 271.168114 -292.516814)
		(end 270.063214 -292.516814)
		(width 0.381)
		(layer "F.Cu")
		(net "GND")
	)
	(segment
		(start 48.854614 -269.566644)
		(end 49.959514 -269.566644)
		(width 0.381)
		(layer "F.Cu")
		(net "GND")
	)
	(segment
		(start 342.664034 -246.086376)
		(end 342.664034 -245.55069)
		(width 0.2032)
		(layer "F.Cu")
		(net "GND")
	)
	(segment
		(start 212.724746 -313.766708)
		(end 211.619846 -313.766708)
		(width 0.381)
		(layer "F.Cu")
		(net "GND")
	)
	(segment
		(start 347.958664 -39.149528)
		(end 347.754702 -38.945566)
		(width 0.2032)
		(layer "F.Cu")
		(net "GND")
	)
	(segment
		(start 419.502082 -250.866656)
		(end 418.397182 -250.866656)
		(width 0.381)
		(layer "F.Cu")
		(net "GND")
	)
	(segment
		(start 101.772466 -235.506006)
		(end 101.772212 -234.970066)
		(width 0.2032)
		(layer "F.Cu")
		(net "GND")
	)
	(segment
		(start 93.893894 -255.547368)
		(end 93.894148 -255.547622)
		(width 0.2032)
		(layer "F.Cu")
		(net "GND")
	)
	(segment
		(start 344.183462 -267.220192)
		(end 344.183462 -267.755878)
		(width 0.2032)
		(layer "F.Cu")
		(net "GND")
	)
	(segment
		(start 276.373082 -314.616592)
		(end 275.268182 -314.616592)
		(width 0.381)
		(layer "F.Cu")
		(net "GND")
	)
	(segment
		(start 135.006842 -38.049708)
		(end 134.067042 -38.049708)
		(width 0.3556)
		(layer "F.Cu")
		(net "GND")
	)
	(segment
		(start 184.439814 -271.266666)
		(end 185.544714 -271.266666)
		(width 0.381)
		(layer "F.Cu")
		(net "GND")
	)
	(segment
		(start 433.484782 -222.816674)
		(end 434.589682 -222.816674)
		(width 0.381)
		(layer "F.Cu")
		(net "GND")
	)
	(segment
		(start 346.995496 -26.404316)
		(end 346.995496 -25.788366)
		(width 0.381)
		(layer "F.Cu")
		(net "GND")
	)
	(segment
		(start 436.928514 -242.3668)
		(end 438.033414 -242.3668)
		(width 0.381)
		(layer "F.Cu")
		(net "GND")
	)
	(segment
		(start 337.604862 -275.35886)
		(end 337.604862 -275.8948)
		(width 0.2032)
		(layer "F.Cu")
		(net "GND")
	)
	(segment
		(start 196.532246 -287.416748)
		(end 195.427346 -287.416748)
		(width 0.381)
		(layer "F.Cu")
		(net "GND")
	)
	(segment
		(start 380.725934 -220.855794)
		(end 380.725934 -220.319854)
		(width 0.2032)
		(layer "F.Cu")
		(net "GND")
	)
	(segment
		(start 44.754546 -306.116736)
		(end 45.859446 -306.116736)
		(width 0.381)
		(layer "F.Cu")
		(net "GND")
	)
	(segment
		(start 129.966466 -250.155964)
		(end 129.966212 -250.15571)
		(width 0.2032)
		(layer "F.Cu")
		(net "GND")
	)
	(segment
		(start 134.775448 -257.988816)
		(end 134.775194 -257.98907)
		(width 0.2032)
		(layer "F.Cu")
		(net "GND")
	)
	(segment
		(start 260.180582 -261.066788)
		(end 259.075682 -261.066788)
		(width 0.381)
		(layer "F.Cu")
		(net "GND")
	)
	(segment
		(start 301.343314 -261.916672)
		(end 302.448214 -261.916672)
		(width 0.3556)
		(layer "F.Cu")
		(net "GND")
	)
	(segment
		(start 275.268182 -299.316648)
		(end 274.163282 -299.316648)
		(width 0.381)
		(layer "F.Cu")
		(net "GND")
	)
	(segment
		(start 294.904414 -250.016772)
		(end 293.799514 -250.016772)
		(width 0.381)
		(layer "F.Cu")
		(net "GND")
	)
	(segment
		(start 204.076046 -238.966756)
		(end 205.180946 -238.966756)
		(width 0.381)
		(layer "F.Cu")
		(net "GND")
	)
	(segment
		(start 374.61698 -226.553268)
		(end 374.61698 -226.017582)
		(width 0.254)
		(layer "F.Cu")
		(net "GND")
	)
	(segment
		(start 304.338482 -278.916638)
		(end 305.443382 -278.916638)
		(width 0.381)
		(layer "F.Cu")
		(net "GND")
	)
	(segment
		(start 419.502082 -280.61666)
		(end 418.397182 -280.61666)
		(width 0.381)
		(layer "F.Cu")
		(net "GND")
	)
	(segment
		(start 194.30873 -358.206548)
		(end 194.30873 -357.165148)
		(width 0.3556)
		(layer "F.Cu")
		(net "GND")
	)
	(segment
		(start 196.532246 -295.06672)
		(end 195.427346 -295.06672)
		(width 0.381)
		(layer "F.Cu")
		(net "GND")
	)
	(segment
		(start 136.545066 -250.155964)
		(end 136.545066 -249.620024)
		(width 0.254)
		(layer "F.Cu")
		(net "GND")
	)
	(segment
		(start 173.900846 -229.616762)
		(end 172.795946 -229.616762)
		(width 0.381)
		(layer "F.Cu")
		(net "GND")
	)
	(segment
		(start 185.355738 -109.775498)
		(end 185.755788 -109.375448)
		(width 0.3556)
		(layer "F.Cu")
		(net "GND")
	)
	(segment
		(start 434.113178 -184.24144)
		(end 434.113178 -185.026046)
		(width 0.3556)
		(layer "F.Cu")
		(net "GND")
	)
	(segment
		(start 336.55508 -240.388902)
		(end 336.55508 -239.853216)
		(width 0.2032)
		(layer "F.Cu")
		(net "GND")
	)
	(segment
		(start 181.444646 -217.716608)
		(end 180.339746 -217.716608)
		(width 0.381)
		(layer "F.Cu")
		(net "GND")
	)
	(segment
		(start 173.900846 -208.366614)
		(end 175.231552 -208.366614)
		(width 0.381)
		(layer "F.Cu")
		(net "GND")
	)
	(segment
		(start 449.677282 -221.116652)
		(end 448.572382 -221.116652)
		(width 0.381)
		(layer "F.Cu")
		(net "GND")
	)
	(segment
		(start 308.887114 -276.366732)
		(end 310.207914 -276.366732)
		(width 0.381)
		(layer "F.Cu")
		(net "GND")
	)
	(segment
		(start 297.899582 -249.166634)
		(end 299.004482 -249.166634)
		(width 0.381)
		(layer "F.Cu")
		(net "GND")
	)
	(segment
		(start 347.363034 -236.319568)
		(end 347.363034 -235.783882)
		(width 0.2032)
		(layer "F.Cu")
		(net "GND")
	)
	(segment
		(start 271.168114 -216.016586)
		(end 270.063214 -216.016586)
		(width 0.381)
		(layer "F.Cu")
		(net "GND")
	)
	(segment
		(start 375.55678 -222.76181)
		(end 375.557034 -222.761556)
		(width 0.254)
		(layer "F.Cu")
		(net "GND")
	)
	(segment
		(start 333.26578 -218.414346)
		(end 333.26578 -217.974672)
		(width 0.2032)
		(layer "F.Cu")
		(net "GND")
	)
	(segment
		(start 98.123248 -259.081016)
		(end 98.123248 -259.616956)
		(width 0.2032)
		(layer "F.Cu")
		(net "GND")
	)
	(segment
		(start 66.67246 -30.1625)
		(end 66.67246 -29.29001)
		(width 0.254)
		(layer "F.Cu")
		(net "GND")
	)
	(segment
		(start 312.01868 -14.950948)
		(end 312.709052 -15.64132)
		(width 0.3556)
		(layer "F.Cu")
		(net "GND")
	)
	(segment
		(start 462.555082 -204.116686)
		(end 463.659982 -204.116686)
		(width 0.381)
		(layer "F.Cu")
		(net "GND")
	)
	(segment
		(start 387.026404 -239.57534)
		(end 387.30428 -239.853216)
		(width 0.254)
		(layer "F.Cu")
		(net "GND")
	)
	(segment
		(start 96.17583 -55.209948)
		(end 95.56623 -55.209948)
		(width 0.3556)
		(layer "F.Cu")
		(net "GND")
	)
	(segment
		(start 59.842146 -290.816792)
		(end 60.947046 -290.816792)
		(width 0.381)
		(layer "F.Cu")
		(net "GND")
	)
	(segment
		(start 215.719914 -282.316682)
		(end 216.824814 -282.316682)
		(width 0.381)
		(layer "F.Cu")
		(net "GND")
	)
	(segment
		(start 180.339746 -258.516628)
		(end 181.444646 -258.516628)
		(width 0.381)
		(layer "F.Cu")
		(net "GND")
	)
	(segment
		(start 385.534662 -268.84757)
		(end 384.594862 -269.38351)
		(width 0.254)
		(layer "F.Cu")
		(net "GND")
	)
	(segment
		(start 110.340648 -256.361438)
		(end 110.340394 -256.361692)
		(width 0.254)
		(layer "F.Cu")
		(net "GND")
	)
	(segment
		(start 386.364734 -217.064336)
		(end 386.364734 -217.600276)
		(width 0.2032)
		(layer "F.Cu")
		(net "GND")
	)
	(segment
		(start 169.149014 -294.216582)
		(end 170.457114 -294.216582)
		(width 0.381)
		(layer "F.Cu")
		(net "GND")
	)
	(segment
		(start 343.243916 -267.219938)
		(end 343.243662 -267.220192)
		(width 0.2032)
		(layer "F.Cu")
		(net "GND")
	)
	(segment
		(start 138.064494 -277.800562)
		(end 138.534394 -277.522432)
		(width 0.254)
		(layer "F.Cu")
		(net "GND")
	)
	(segment
		(start 443.853316 -30.820106)
		(end 443.853316 -29.575506)
		(width 0.17272)
		(layer "F.Cu")
		(net "GND")
	)
	(segment
		(start 196.532246 -265.316716)
		(end 195.427346 -265.316716)
		(width 0.381)
		(layer "F.Cu")
		(net "GND")
	)
	(segment
		(start 18.679414 -278.916638)
		(end 19.784314 -278.916638)
		(width 0.381)
		(layer "F.Cu")
		(net "GND")
	)
	(segment
		(start 89.555066 -225.739198)
		(end 89.555066 -225.203512)
		(width 0.2032)
		(layer "F.Cu")
		(net "GND")
	)
	(segment
		(start 195.427346 -246.616728)
		(end 196.532246 -246.616728)
		(width 0.381)
		(layer "F.Cu")
		(net "GND")
	)
	(segment
		(start 171.562014 -303.566576)
		(end 170.457114 -303.566576)
		(width 0.381)
		(layer "F.Cu")
		(net "GND")
	)
	(segment
		(start 452.016114 -309.51678)
		(end 450.911214 -309.51678)
		(width 0.381)
		(layer "F.Cu")
		(net "GND")
	)
	(segment
		(start 49.959514 -202.416664)
		(end 51.064414 -202.416664)
		(width 0.381)
		(layer "F.Cu")
		(net "GND")
	)
	(segment
		(start 444.472314 -203.266802)
		(end 443.367414 -203.266802)
		(width 0.381)
		(layer "F.Cu")
		(net "GND")
	)
	(segment
		(start 210.514946 -221.96679)
		(end 211.619846 -221.96679)
		(width 0.381)
		(layer "F.Cu")
		(net "GND")
	)
	(segment
		(start 382.245362 -264.778236)
		(end 382.245616 -265.314176)
		(width 0.2032)
		(layer "F.Cu")
		(net "GND")
	)
	(segment
		(start 359.11028 -232.250234)
		(end 359.11028 -231.714548)
		(width 0.2032)
		(layer "F.Cu")
		(net "GND")
	)
	(segment
		(start 15.684246 -227.066602)
		(end 16.789146 -227.066602)
		(width 0.381)
		(layer "F.Cu")
		(net "GND")
	)
	(segment
		(start 299.700188 -393.77239)
		(end 299.700188 -390.459976)
		(width 0.4572)
		(layer "F.Cu")
		(net "GND")
	)
	(segment
		(start 85.325712 -237.947454)
		(end 85.325712 -237.411768)
		(width 0.254)
		(layer "F.Cu")
		(net "GND")
	)
	(segment
		(start 173.900846 -236.416596)
		(end 175.286416 -236.416596)
		(width 0.381)
		(layer "F.Cu")
		(net "GND")
	)
	(segment
		(start 380.365762 -261.522718)
		(end 380.365762 -262.058658)
		(width 0.2032)
		(layer "F.Cu")
		(net "GND")
	)
	(segment
		(start 333.735934 -245.27256)
		(end 334.200246 -245.540276)
		(width 0.2032)
		(layer "F.Cu")
		(net "GND")
	)
	(segment
		(start 236.599984 -56.965088)
		(end 237.615984 -56.965088)
		(width 0.381)
		(layer "F.Cu")
		(net "GND")
	)
	(segment
		(start 91.074494 -277.800562)
		(end 91.074494 -278.336502)
		(width 0.2032)
		(layer "F.Cu")
		(net "GND")
	)
	(segment
		(start 97.653094 -258.2672)
		(end 97.653094 -258.802886)
		(width 0.2032)
		(layer "F.Cu")
		(net "GND")
	)
	(segment
		(start 382.605534 -245.27256)
		(end 382.60528 -245.272306)
		(width 0.2032)
		(layer "F.Cu")
		(net "GND")
	)
	(segment
		(start 384.015234 -239.57534)
		(end 384.015234 -239.0394)
		(width 0.254)
		(layer "F.Cu")
		(net "GND")
	)
	(segment
		(start 110.340648 -259.616956)
		(end 110.340394 -259.61721)
		(width 0.254)
		(layer "F.Cu")
		(net "GND")
	)
	(segment
		(start 109.400594 -272.103342)
		(end 109.400594 -272.639282)
		(width 0.2032)
		(layer "F.Cu")
		(net "GND")
	)
	(segment
		(start 275.268182 -262.76681)
		(end 274.163282 -262.76681)
		(width 0.381)
		(layer "F.Cu")
		(net "GND")
	)
	(segment
		(start 132.895848 -270.475456)
		(end 132.895594 -271.011396)
		(width 0.2032)
		(layer "F.Cu")
		(net "GND")
	)
	(segment
		(start 419.502082 -284.866588)
		(end 418.397182 -284.866588)
		(width 0.381)
		(layer "F.Cu")
		(net "GND")
	)
	(segment
		(start 329.980798 -46.570646)
		(end 329.980036 -46.570646)
		(width 0.254)
		(layer "F.Cu")
		(net "GND")
	)
	(segment
		(start 100.362512 -226.017582)
		(end 100.362766 -226.017328)
		(width 0.254)
		(layer "F.Cu")
		(net "GND")
	)
	(segment
		(start 381.775716 -280.242264)
		(end 381.775462 -280.778204)
		(width 0.254)
		(layer "F.Cu")
		(net "GND")
	)
	(segment
		(start 337.49488 -230.622348)
		(end 337.49488 -230.086662)
		(width 0.2032)
		(layer "F.Cu")
		(net "GND")
	)
	(segment
		(start 193.088514 -239.81664)
		(end 191.983614 -239.81664)
		(width 0.381)
		(layer "F.Cu")
		(net "GND")
	)
	(segment
		(start 444.472314 -317.166752)
		(end 445.577214 -317.166752)
		(width 0.381)
		(layer "F.Cu")
		(net "GND")
	)
	(segment
		(start 187.883546 -278.066754)
		(end 188.988446 -278.066754)
		(width 0.381)
		(layer "F.Cu")
		(net "GND")
	)
	(segment
		(start 119.738648 -280.242264)
		(end 119.738648 -280.77795)
		(width 0.254)
		(layer "F.Cu")
		(net "GND")
	)
	(segment
		(start 169.352214 -194.766692)
		(end 170.457114 -194.766692)
		(width 0.381)
		(layer "F.Cu")
		(net "GND")
	)
	(segment
		(start 372.377716 -262.336534)
		(end 372.377716 -262.87222)
		(width 0.254)
		(layer "F.Cu")
		(net "GND")
	)
	(segment
		(start 285.150814 -267.016738)
		(end 286.255714 -267.016738)
		(width 0.381)
		(layer "F.Cu")
		(net "GND")
	)
	(segment
		(start 106.111294 -274.54479)
		(end 106.111294 -275.08073)
		(width 0.254)
		(layer "F.Cu")
		(net "GND")
	)
	(segment
		(start 19.784314 -232.166668)
		(end 20.889214 -232.166668)
		(width 0.381)
		(layer "F.Cu")
		(net "GND")
	)
	(segment
		(start 29.666692 -402.917152)
		(end 29.538422 -403.045422)
		(width 0.3556)
		(layer "F.Cu")
		(net "GND")
	)
	(segment
		(start 431.247296 -10.153396)
		(end 431.36693 -10.27303)
		(width 0.3556)
		(layer "F.Cu")
		(net "GND")
	)
	(segment
		(start 312.987182 -213.46668)
		(end 314.092082 -213.46668)
		(width 0.381)
		(layer "F.Cu")
		(net "GND")
	)
	(segment
		(start 456.116182 -272.966688)
		(end 455.011282 -272.966688)
		(width 0.381)
		(layer "F.Cu")
		(net "GND")
	)
	(segment
		(start 178.000914 -205.816708)
		(end 176.896014 -205.816708)
		(width 0.381)
		(layer "F.Cu")
		(net "GND")
	)
	(segment
		(start 97.073466 -224.111566)
		(end 97.073466 -223.575626)
		(width 0.2032)
		(layer "F.Cu")
		(net "GND")
	)
	(segment
		(start 188.988446 -298.466764)
		(end 190.093346 -298.466764)
		(width 0.381)
		(layer "F.Cu")
		(net "GND")
	)
	(segment
		(start 448.572382 -239.81664)
		(end 447.467482 -239.81664)
		(width 0.381)
		(layer "F.Cu")
		(net "GND")
	)
	(segment
		(start 99.422712 -234.156504)
		(end 99.422966 -234.15625)
		(width 0.254)
		(layer "F.Cu")
		(net "GND")
	)
	(segment
		(start 167.461946 -268.71676)
		(end 166.357046 -268.71676)
		(width 0.381)
		(layer "F.Cu")
		(net "GND")
	)
	(segment
		(start 96.243648 -267.219938)
		(end 96.243394 -267.220192)
		(width 0.2032)
		(layer "F.Cu")
		(net "GND")
	)
	(segment
		(start 332.752446 -269.938754)
		(end 332.7527 -269.938246)
		(width 0.2032)
		(layer "F.Cu")
		(net "GND")
	)
	(segment
		(start 307.782214 -272.116804)
		(end 308.887114 -272.116804)
		(width 0.381)
		(layer "F.Cu")
		(net "GND")
	)
	(segment
		(start 300.022514 -313.766708)
		(end 301.343314 -313.766708)
		(width 0.381)
		(layer "F.Cu")
		(net "GND")
	)
	(segment
		(start 98.013266 -232.250488)
		(end 98.013012 -232.250234)
		(width 0.2032)
		(layer "F.Cu")
		(net "GND")
	)
	(segment
		(start 339.014562 -257.175254)
		(end 339.014562 -256.639314)
		(width 0.2032)
		(layer "F.Cu")
		(net "GND")
	)
	(segment
		(start 457.221082 -232.166668)
		(end 456.116182 -232.166668)
		(width 0.381)
		(layer "F.Cu")
		(net "GND")
	)
	(segment
		(start 349.822516 -272.639028)
		(end 349.822262 -272.639282)
		(width 0.2032)
		(layer "F.Cu")
		(net "GND")
	)
	(segment
		(start 293.799514 -272.116804)
		(end 292.694614 -272.116804)
		(width 0.381)
		(layer "F.Cu")
		(net "GND")
	)
	(segment
		(start 18.679414 -312.91657)
		(end 19.784314 -312.91657)
		(width 0.381)
		(layer "F.Cu")
		(net "GND")
	)
	(segment
		(start 23.650702 -402.806408)
		(end 23.041102 -402.806408)
		(width 0.3556)
		(layer "F.Cu")
		(net "GND")
	)
	(segment
		(start 286.255714 -276.366732)
		(end 287.360614 -276.366732)
		(width 0.381)
		(layer "F.Cu")
		(net "GND")
	)
	(segment
		(start 171.562014 -305.266598)
		(end 170.457114 -305.266598)
		(width 0.381)
		(layer "F.Cu")
		(net "GND")
	)
	(segment
		(start 59.842146 -210.916774)
		(end 60.947046 -210.916774)
		(width 0.381)
		(layer "F.Cu")
		(net "GND")
	)
	(segment
		(start 88.255094 -268.033754)
		(end 88.255094 -268.569694)
		(width 0.2032)
		(layer "F.Cu")
		(net "GND")
	)
	(segment
		(start 137.484866 -230.622602)
		(end 137.014966 -230.900478)
		(width 0.254)
		(layer "F.Cu")
		(net "GND")
	)
	(segment
		(start 41.197022 -358.691942)
		(end 40.673782 -358.691942)
		(width 0.381)
		(layer "F.Cu")
		(net "GND")
	)
	(segment
		(start 377.076716 -275.35886)
		(end 377.076716 -275.8948)
		(width 0.2032)
		(layer "F.Cu")
		(net "GND")
	)
	(segment
		(start 394.899896 -50.895504)
		(end 394.899642 -50.89525)
		(width 0.3556)
		(layer "F.Cu")
		(net "GND")
	)
	(segment
		(start 364.438692 -387.119876)
		(end 364.82782 -386.730748)
		(width 0.3556)
		(layer "F.Cu")
		(net "GND")
	)
	(segment
		(start 439.923682 -247.466612)
		(end 441.028582 -247.466612)
		(width 0.381)
		(layer "F.Cu")
		(net "GND")
	)
	(segment
		(start 340.78418 -247.178576)
		(end 340.784434 -247.178322)
		(width 0.2032)
		(layer "F.Cu")
		(net "GND")
	)
	(segment
		(start 259.89788 -47.034196)
		(end 259.89788 -47.643796)
		(width 0.3556)
		(layer "F.Cu")
		(net "GND")
	)
	(segment
		(start 435.823614 -315.46673)
		(end 436.928514 -315.46673)
		(width 0.381)
		(layer "F.Cu")
		(net "GND")
	)
	(segment
		(start 351.12198 -226.553268)
		(end 351.12198 -226.017582)
		(width 0.254)
		(layer "F.Cu")
		(net "GND")
	)
	(segment
		(start 186.649614 -277.216616)
		(end 185.544714 -277.216616)
		(width 0.381)
		(layer "F.Cu")
		(net "GND")
	)
	(segment
		(start 129.496312 -223.297496)
		(end 129.496312 -222.76181)
		(width 0.254)
		(layer "F.Cu")
		(net "GND")
	)
	(segment
		(start 8.140446 -261.916672)
		(end 9.245346 -261.916672)
		(width 0.381)
		(layer "F.Cu")
		(net "GND")
	)
	(segment
		(start 214.615014 -245.76659)
		(end 215.719914 -245.76659)
		(width 0.381)
		(layer "F.Cu")
		(net "GND")
	)
	(segment
		(start 22.123146 -292.516814)
		(end 23.228046 -292.516814)
		(width 0.381)
		(layer "F.Cu")
		(net "GND")
	)
	(segment
		(start 236.599984 -55.16499)
		(end 237.615984 -55.16499)
		(width 0.381)
		(layer "F.Cu")
		(net "GND")
	)
	(segment
		(start 272.273014 -216.016586)
		(end 271.168114 -216.016586)
		(width 0.381)
		(layer "F.Cu")
		(net "GND")
	)
	(segment
		(start 129.966466 -230.622602)
		(end 129.966212 -230.622348)
		(width 0.2032)
		(layer "F.Cu")
		(net "GND")
	)
	(segment
		(start 416.584384 -52.27701)
		(end 414.756346 -54.105048)
		(width 0.3556)
		(layer "F.Cu")
		(net "GND")
	)
	(segment
		(start 353.94138 -229.808786)
		(end 353.941634 -229.808532)
		(width 0.2032)
		(layer "F.Cu")
		(net "GND")
	)
	(segment
		(start 263.624314 -278.066754)
		(end 264.729214 -278.066754)
		(width 0.381)
		(layer "F.Cu")
		(net "GND")
	)
	(segment
		(start 291.836348 -18.714466)
		(end 290.983162 -18.714466)
		(width 0.3556)
		(layer "F.Cu")
		(net "GND")
	)
	(segment
		(start 211.619846 -195.616576)
		(end 212.724746 -195.616576)
		(width 0.381)
		(layer "F.Cu")
		(net "GND")
	)
	(segment
		(start 115.509294 -271.289272)
		(end 115.509548 -271.825212)
		(width 0.2032)
		(layer "F.Cu")
		(net "GND")
	)
	(segment
		(start 367.208562 -282.683966)
		(end 367.208562 -283.219906)
		(width 0.254)
		(layer "F.Cu")
		(net "GND")
	)
	(segment
		(start 102.712012 -230.622348)
		(end 102.712012 -230.086662)
		(width 0.2032)
		(layer "F.Cu")
		(net "GND")
	)
	(segment
		(start 89.554812 -238.76127)
		(end 89.554812 -238.225584)
		(width 0.254)
		(layer "F.Cu")
		(net "GND")
	)
	(segment
		(start 157.08884 -30.941518)
		(end 157.08884 -30.312868)
		(width 0.3556)
		(layer "F.Cu")
		(net "GND")
	)
	(segment
		(start 377.43638 -241.203226)
		(end 377.436634 -241.202972)
		(width 0.2032)
		(layer "F.Cu")
		(net "GND")
	)
	(segment
		(start 420.991538 -165.018974)
		(end 421.618156 -165.018974)
		(width 0.381)
		(layer "F.Cu")
		(net "GND")
	)
	(segment
		(start 150.54834 -39.710868)
		(end 150.697946 -39.561262)
		(width 0.3556)
		(layer "F.Cu")
		(net "GND")
	)
	(segment
		(start 20.889214 -198.166736)
		(end 19.784314 -198.166736)
		(width 0.381)
		(layer "F.Cu")
		(net "GND")
	)
	(segment
		(start 429.566832 -11.26998)
		(end 429.566832 -12.37488)
		(width 0.3556)
		(layer "F.Cu")
		(net "GND")
	)
	(segment
		(start 393.046966 -11.26998)
		(end 393.046966 -12.37488)
		(width 0.3556)
		(layer "F.Cu")
		(net "GND")
	)
	(segment
		(start 97.183448 -272.103342)
		(end 97.183448 -272.639282)
		(width 0.2032)
		(layer "F.Cu")
		(net "GND")
	)
	(segment
		(start 418.397182 -194.766692)
		(end 417.292282 -194.766692)
		(width 0.381)
		(layer "F.Cu")
		(net "GND")
	)
	(segment
		(start 325.199248 -346.885006)
		(end 325.077836 -346.763594)
		(width 0.3556)
		(layer "F.Cu")
		(net "GND")
	)
	(segment
		(start 365.799116 -281.869896)
		(end 365.799116 -282.405836)
		(width 0.254)
		(layer "F.Cu")
		(net "GND")
	)
	(segment
		(start 427.045882 -284.866588)
		(end 425.940982 -284.866588)
		(width 0.381)
		(layer "F.Cu")
		(net "GND")
	)
	(segment
		(start 152.81783 -112.867948)
		(end 152.20188 -112.867948)
		(width 0.3556)
		(layer "F.Cu")
		(net "GND")
	)
	(segment
		(start 108.820712 -226.017582)
		(end 108.820966 -226.017328)
		(width 0.254)
		(layer "F.Cu")
		(net "GND")
	)
	(segment
		(start 213.11489 -130.923538)
		(end 211.99729 -130.923538)
		(width 0.3556)
		(layer "F.Cu")
		(net "GND")
	)
	(segment
		(start 187.883546 -225.36658)
		(end 188.988446 -225.36658)
		(width 0.381)
		(layer "F.Cu")
		(net "GND")
	)
	(segment
		(start 262.519414 -208.366614)
		(end 263.624314 -208.366614)
		(width 0.381)
		(layer "F.Cu")
		(net "GND")
	)
	(segment
		(start 14.579346 -214.316564)
		(end 15.684246 -214.316564)
		(width 0.381)
		(layer "F.Cu")
		(net "GND")
	)
	(segment
		(start 197.637146 -283.166566)
		(end 196.532246 -283.166566)
		(width 0.381)
		(layer "F.Cu")
		(net "GND")
	)
	(segment
		(start 275.268182 -275.516594)
		(end 274.163282 -275.516594)
		(width 0.381)
		(layer "F.Cu")
		(net "GND")
	)
	(segment
		(start 95.663512 -223.297496)
		(end 95.663512 -222.76181)
		(width 0.254)
		(layer "F.Cu")
		(net "GND")
	)
	(segment
		(start 93.783912 -242.830858)
		(end 93.783912 -242.295172)
		(width 0.2032)
		(layer "F.Cu")
		(net "GND")
	)
	(segment
		(start 39.420546 -203.266802)
		(end 38.315646 -203.266802)
		(width 0.381)
		(layer "F.Cu")
		(net "GND")
	)
	(segment
		(start 351.702116 -264.500106)
		(end 351.701862 -264.50036)
		(width 0.254)
		(layer "F.Cu")
		(net "GND")
	)
	(segment
		(start 129.136648 -284.033468)
		(end 129.136394 -284.033722)
		(width 0.254)
		(layer "F.Cu")
		(net "GND")
	)
	(segment
		(start 128.666494 -255.011682)
		(end 128.666494 -255.547368)
		(width 0.2032)
		(layer "F.Cu")
		(net "GND")
	)
	(segment
		(start 413.192214 -296.766742)
		(end 414.297114 -296.766742)
		(width 0.381)
		(layer "F.Cu")
		(net "GND")
	)
	(segment
		(start 104.701848 -285.6611)
		(end 104.701594 -285.661354)
		(width 0.254)
		(layer "F.Cu")
		(net "GND")
	)
	(segment
		(start 34.871914 -314.616592)
		(end 35.976814 -314.616592)
		(width 0.381)
		(layer "F.Cu")
		(net "GND")
	)
	(segment
		(start 286.359092 -344.700352)
		(end 287.2994 -344.700352)
		(width 0.508)
		(layer "F.Cu")
		(net "GND")
	)
	(segment
		(start 34.871914 -219.41663)
		(end 35.976814 -219.41663)
		(width 0.381)
		(layer "F.Cu")
		(net "GND")
	)
	(segment
		(start 441.028582 -291.666676)
		(end 442.133482 -291.666676)
		(width 0.381)
		(layer "F.Cu")
		(net "GND")
	)
	(segment
		(start 87.205312 -223.297496)
		(end 87.205312 -222.76181)
		(width 0.2032)
		(layer "F.Cu")
		(net "GND")
	)
	(segment
		(start 433.484782 -250.866656)
		(end 434.589682 -250.866656)
		(width 0.381)
		(layer "F.Cu")
		(net "GND")
	)
	(segment
		(start 188.988446 -306.116736)
		(end 190.093346 -306.116736)
		(width 0.381)
		(layer "F.Cu")
		(net "GND")
	)
	(segment
		(start 419.502082 -228.766624)
		(end 418.397182 -228.766624)
		(width 0.381)
		(layer "F.Cu")
		(net "GND")
	)
	(segment
		(start 190.093346 -229.616762)
		(end 188.988446 -229.616762)
		(width 0.381)
		(layer "F.Cu")
		(net "GND")
	)
	(segment
		(start 261.285482 -314.616592)
		(end 260.180582 -314.616592)
		(width 0.381)
		(layer "F.Cu")
		(net "GND")
	)
	(segment
		(start 20.889214 -222.816674)
		(end 19.784314 -222.816674)
		(width 0.381)
		(layer "F.Cu")
		(net "GND")
	)
	(segment
		(start 381.19558 -222.76181)
		(end 381.195834 -222.761556)
		(width 0.254)
		(layer "F.Cu")
		(net "GND")
	)
	(segment
		(start 65.047114 -288.266632)
		(end 66.152014 -288.266632)
		(width 0.381)
		(layer "F.Cu")
		(net "GND")
	)
	(segment
		(start 30.771846 -292.516814)
		(end 31.876746 -292.516814)
		(width 0.381)
		(layer "F.Cu")
		(net "GND")
	)
	(segment
		(start 66.86296 -61.558678)
		(end 67.397122 -62.09284)
		(width 0.3556)
		(layer "F.Cu")
		(net "GND")
	)
	(segment
		(start 457.221082 -235.566712)
		(end 456.116182 -235.566712)
		(width 0.381)
		(layer "F.Cu")
		(net "GND")
	)
	(segment
		(start 278.711914 -315.46673)
		(end 279.816814 -315.46673)
		(width 0.381)
		(layer "F.Cu")
		(net "GND")
	)
	(segment
		(start 101.882448 -274.26666)
		(end 101.882194 -274.266914)
		(width 0.254)
		(layer "F.Cu")
		(net "GND")
	)
	(segment
		(start 89.554812 -243.644674)
		(end 89.554812 -243.108988)
		(width 0.2032)
		(layer "F.Cu")
		(net "GND")
	)
	(segment
		(start 86.845648 -285.125414)
		(end 86.845648 -285.6611)
		(width 0.2032)
		(layer "F.Cu")
		(net "GND")
	)
	(segment
		(start 213.741 -121.2088)
		(end 213.6394 -121.1072)
		(width 0.3556)
		(layer "F.Cu")
		(net "GND")
	)
	(segment
		(start 202.971146 -231.316784)
		(end 204.076046 -231.316784)
		(width 0.381)
		(layer "F.Cu")
		(net "GND")
	)
	(segment
		(start 173.900846 -234.716574)
		(end 172.795946 -234.716574)
		(width 0.381)
		(layer "F.Cu")
		(net "GND")
	)
	(segment
		(start 25.999186 -126.332996)
		(end 26.63825 -126.332996)
		(width 0.381)
		(layer "F.Cu")
		(net "GND")
	)
	(segment
		(start 49.959514 -294.216582)
		(end 48.638714 -294.216582)
		(width 0.381)
		(layer "F.Cu")
		(net "GND")
	)
	(segment
		(start 310.207914 -287.416748)
		(end 308.887114 -287.416748)
		(width 0.381)
		(layer "F.Cu")
		(net "GND")
	)
	(segment
		(start 116.339112 -222.76181)
		(end 116.339366 -222.761556)
		(width 0.254)
		(layer "F.Cu")
		(net "GND")
	)
	(segment
		(start 379.786134 -230.622602)
		(end 379.786134 -230.086662)
		(width 0.2032)
		(layer "F.Cu")
		(net "GND")
	)
	(segment
		(start 204.076046 -248.31675)
		(end 205.180946 -248.31675)
		(width 0.381)
		(layer "F.Cu")
		(net "GND")
	)
	(segment
		(start 135.605012 -237.133638)
		(end 135.605012 -236.597952)
		(width 0.254)
		(layer "F.Cu")
		(net "GND")
	)
	(segment
		(start 353.00158 -222.76181)
		(end 353.001834 -222.761556)
		(width 0.254)
		(layer "F.Cu")
		(net "GND")
	)
	(segment
		(start 281.707082 -207.51673)
		(end 282.811982 -207.51673)
		(width 0.381)
		(layer "F.Cu")
		(net "GND")
	)
	(segment
		(start 290.857432 -375.745502)
		(end 290.857432 -375.089928)
		(width 0.3556)
		(layer "F.Cu")
		(net "GND")
	)
	(segment
		(start 382.245362 -275.080476)
		(end 382.245616 -275.08073)
		(width 0.2032)
		(layer "F.Cu")
		(net "GND")
	)
	(segment
		(start 435.823614 -278.066754)
		(end 436.928514 -278.066754)
		(width 0.381)
		(layer "F.Cu")
		(net "GND")
	)
	(segment
		(start 342.66378 -229.808786)
		(end 342.66378 -229.272846)
		(width 0.2032)
		(layer "F.Cu")
		(net "GND")
	)
	(segment
		(start 56.398414 -239.81664)
		(end 57.503314 -239.81664)
		(width 0.381)
		(layer "F.Cu")
		(net "GND")
	)
	(segment
		(start 444.472314 -298.466764)
		(end 443.367414 -298.466764)
		(width 0.381)
		(layer "F.Cu")
		(net "GND")
	)
	(segment
		(start 100.942648 -261.244588)
		(end 100.942394 -261.244842)
		(width 0.254)
		(layer "F.Cu")
		(net "GND")
	)
	(segment
		(start 420.156894 -8.320024)
		(end 420.156894 -9.424924)
		(width 0.3556)
		(layer "F.Cu")
		(net "GND")
	)
	(segment
		(start 457.221082 -244.066568)
		(end 456.116182 -244.066568)
		(width 0.381)
		(layer "F.Cu")
		(net "GND")
	)
	(segment
		(start 410.853382 -228.766624)
		(end 409.748482 -228.766624)
		(width 0.381)
		(layer "F.Cu")
		(net "GND")
	)
	(segment
		(start 340.894162 -278.336248)
		(end 340.894416 -278.336502)
		(width 0.2032)
		(layer "F.Cu")
		(net "GND")
	)
	(segment
		(start 116.449094 -274.54479)
		(end 116.449094 -275.08073)
		(width 0.254)
		(layer "F.Cu")
		(net "GND")
	)
	(segment
		(start 113.629694 -274.54479)
		(end 113.629694 -275.08073)
		(width 0.254)
		(layer "F.Cu")
		(net "GND")
	)
	(segment
		(start 186.649614 -284.866588)
		(end 185.544714 -284.866588)
		(width 0.381)
		(layer "F.Cu")
		(net "GND")
	)
	(segment
		(start 52.72913 -153.380186)
		(end 52.500276 -153.380186)
		(width 0.2032)
		(layer "F.Cu")
		(net "GND")
	)
	(segment
		(start 447.467482 -196.466714)
		(end 448.572382 -196.466714)
		(width 0.381)
		(layer "F.Cu")
		(net "GND")
	)
	(segment
		(start 380.365762 -268.033754)
		(end 380.366016 -268.569694)
		(width 0.2032)
		(layer "F.Cu")
		(net "GND")
	)
	(segment
		(start 380.25578 -220.041978)
		(end 380.25578 -219.506292)
		(width 0.254)
		(layer "F.Cu")
		(net "GND")
	)
	(segment
		(start 254.975614 -229.616762)
		(end 256.080514 -229.616762)
		(width 0.381)
		(layer "F.Cu")
		(net "GND")
	)
	(segment
		(start 124.797312 -223.297496)
		(end 124.797312 -222.76181)
		(width 0.254)
		(layer "F.Cu")
		(net "GND")
	)
	(segment
		(start 385.56946 -286.788098)
		(end 385.56946 -287.381696)
		(width 0.254)
		(layer "F.Cu")
		(net "GND")
	)
	(segment
		(start 262.519414 -229.616762)
		(end 263.624314 -229.616762)
		(width 0.381)
		(layer "F.Cu")
		(net "GND")
	)
	(segment
		(start 95.193866 -250.155964)
		(end 95.193612 -250.15571)
		(width 0.2032)
		(layer "F.Cu")
		(net "GND")
	)
	(segment
		(start 463.659982 -294.216582)
		(end 462.555082 -294.216582)
		(width 0.381)
		(layer "F.Cu")
		(net "GND")
	)
	(segment
		(start 178.000914 -258.516628)
		(end 176.896014 -258.516628)
		(width 0.381)
		(layer "F.Cu")
		(net "GND")
	)
	(segment
		(start 293.799514 -258.516628)
		(end 292.694614 -258.516628)
		(width 0.381)
		(layer "F.Cu")
		(net "GND")
	)
	(segment
		(start 409.748482 -261.066788)
		(end 410.853382 -261.066788)
		(width 0.381)
		(layer "F.Cu")
		(net "GND")
	)
	(segment
		(start 408.17292 -368.280188)
		(end 407.627074 -368.826034)
		(width 0.381)
		(layer "F.Cu")
		(net "GND")
	)
	(segment
		(start 294.904414 -242.3668)
		(end 293.799514 -242.3668)
		(width 0.381)
		(layer "F.Cu")
		(net "GND")
	)
	(segment
		(start 416.484562 -164.585904)
		(end 416.484562 -164.879528)
		(width 0.2032)
		(layer "F.Cu")
		(net "GND")
	)
	(segment
		(start 106.471466 -214.344758)
		(end 106.471466 -213.732618)
		(width 0.254)
		(layer "F.Cu")
		(net "GND")
	)
	(segment
		(start 334.785716 -285.125414)
		(end 334.785716 -285.6611)
		(width 0.2032)
		(layer "F.Cu")
		(net "GND")
	)
	(segment
		(start 14.265402 -105.937812)
		(end 14.265402 -106.32567)
		(width 0.3556)
		(layer "F.Cu")
		(net "GND")
	)
	(segment
		(start 58.53303 -40.956738)
		(end 58.53303 -40.404034)
		(width 0.3556)
		(layer "F.Cu")
		(net "GND")
	)
	(segment
		(start 127.616712 -226.017582)
		(end 127.616966 -226.017328)
		(width 0.254)
		(layer "F.Cu")
		(net "GND")
	)
	(segment
		(start 352.641916 -265.592306)
		(end 352.641662 -265.592306)
		(width 0.2032)
		(layer "F.Cu")
		(net "GND")
	)
	(segment
		(start 95.13824 -414.886394)
		(end 95.13824 -414.48482)
		(width 0.3556)
		(layer "F.Cu")
		(net "GND")
	)
	(segment
		(start 43.520614 -211.766658)
		(end 42.415714 -211.766658)
		(width 0.381)
		(layer "F.Cu")
		(net "GND")
	)
	(segment
		(start 110.230666 -237.133892)
		(end 110.230666 -236.597952)
		(width 0.254)
		(layer "F.Cu")
		(net "GND")
	)
	(segment
		(start 207.071214 -266.1666)
		(end 208.176114 -266.1666)
		(width 0.381)
		(layer "F.Cu")
		(net "GND")
	)
	(segment
		(start 423.95648 -51.22418)
		(end 423.67962 -50.94732)
		(width 0.3556)
		(layer "F.Cu")
		(net "GND")
	)
	(segment
		(start 94.723712 -241.203226)
		(end 94.723966 -241.202972)
		(width 0.2032)
		(layer "F.Cu")
		(net "GND")
	)
	(segment
		(start 285.150814 -276.366732)
		(end 286.255714 -276.366732)
		(width 0.381)
		(layer "F.Cu")
		(net "GND")
	)
	(segment
		(start 87.785194 -259.081016)
		(end 87.315294 -258.80314)
		(width 0.254)
		(layer "F.Cu")
		(net "GND")
	)
	(segment
		(start 182.549546 -285.716726)
		(end 181.444646 -285.716726)
		(width 0.381)
		(layer "F.Cu")
		(net "GND")
	)
	(segment
		(start 334.03794 -338.951316)
		(end 333.679292 -339.309964)
		(width 0.2032)
		(layer "F.Cu")
		(net "GND")
	)
	(segment
		(start 384.595116 -281.869896)
		(end 384.595116 -282.405582)
		(width 0.254)
		(layer "F.Cu")
		(net "GND")
	)
	(segment
		(start 462.555082 -205.816708)
		(end 463.659982 -205.816708)
		(width 0.381)
		(layer "F.Cu")
		(net "GND")
	)
	(segment
		(start 374.61698 -226.017582)
		(end 374.617234 -226.017328)
		(width 0.254)
		(layer "F.Cu")
		(net "GND")
	)
	(segment
		(start 22.123146 -212.616796)
		(end 23.228046 -212.616796)
		(width 0.381)
		(layer "F.Cu")
		(net "GND")
	)
	(segment
		(start 53.403246 -244.916706)
		(end 54.508146 -244.916706)
		(width 0.381)
		(layer "F.Cu")
		(net "GND")
	)
	(segment
		(start 152.985724 -36.341558)
		(end 152.09393 -36.341558)
		(width 0.3556)
		(layer "F.Cu")
		(net "GND")
	)
	(segment
		(start 53.403246 -306.116736)
		(end 54.508146 -306.116736)
		(width 0.381)
		(layer "F.Cu")
		(net "GND")
	)
	(segment
		(start 331.897482 -39.295324)
		(end 332.263242 -39.403528)
		(width 0.2032)
		(layer "F.Cu")
		(net "GND")
	)
	(segment
		(start 385.534662 -267.219938)
		(end 385.534662 -267.755878)
		(width 0.254)
		(layer "F.Cu")
		(net "GND")
	)
	(segment
		(start 348.882716 -286.7533)
		(end 348.882716 -287.288986)
		(width 0.254)
		(layer "F.Cu")
		(net "GND")
	)
	(segment
		(start 108.820712 -223.297496)
		(end 108.820712 -222.76181)
		(width 0.254)
		(layer "F.Cu")
		(net "GND")
	)
	(segment
		(start 11.135614 -267.866622)
		(end 12.240514 -267.866622)
		(width 0.381)
		(layer "F.Cu")
		(net "GND")
	)
	(segment
		(start 282.811982 -284.866588)
		(end 283.916882 -284.866588)
		(width 0.381)
		(layer "F.Cu")
		(net "GND")
	)
	(segment
		(start 353.94138 -222.76181)
		(end 353.941634 -222.761556)
		(width 0.254)
		(layer "F.Cu")
		(net "GND")
	)
	(segment
		(start 341.72398 -228.1809)
		(end 341.724234 -228.180646)
		(width 0.2032)
		(layer "F.Cu")
		(net "GND")
	)
	(segment
		(start 135.605266 -237.133892)
		(end 135.605012 -237.133638)
		(width 0.254)
		(layer "F.Cu")
		(net "GND")
	)
	(segment
		(start 116.449094 -285.939484)
		(end 116.449094 -286.47517)
		(width 0.254)
		(layer "F.Cu")
		(net "GND")
	)
	(segment
		(start 113.482374 -37.01034)
		(end 112.694212 -37.01034)
		(width 0.3556)
		(layer "F.Cu")
		(net "GND")
	)
	(segment
		(start 127.726694 -262.058404)
		(end 127.726948 -262.058658)
		(width 0.254)
		(layer "F.Cu")
		(net "GND")
	)
	(segment
		(start 386.474716 -283.497782)
		(end 386.474462 -283.498036)
		(width 0.2032)
		(layer "F.Cu")
		(net "GND")
	)
	(segment
		(start 254.975614 -265.316716)
		(end 256.080514 -265.316716)
		(width 0.381)
		(layer "F.Cu")
		(net "GND")
	)
	(segment
		(start 290.355782 -233.86669)
		(end 291.460682 -233.86669)
		(width 0.381)
		(layer "F.Cu")
		(net "GND")
	)
	(segment
		(start 453.121014 -278.066754)
		(end 452.016114 -278.066754)
		(width 0.381)
		(layer "F.Cu")
		(net "GND")
	)
	(segment
		(start 164.018214 -202.416664)
		(end 162.913314 -202.416664)
		(width 0.381)
		(layer "F.Cu")
		(net "GND")
	)
	(segment
		(start 27.328114 -295.916604)
		(end 28.433014 -295.916604)
		(width 0.381)
		(layer "F.Cu")
		(net "GND")
	)
	(segment
		(start 178.000914 -282.316682)
		(end 179.105814 -282.316682)
		(width 0.381)
		(layer "F.Cu")
		(net "GND")
	)
	(segment
		(start 48.854614 -250.866656)
		(end 49.959514 -250.866656)
		(width 0.381)
		(layer "F.Cu")
		(net "GND")
	)
	(segment
		(start 65.047114 -312.91657)
		(end 66.367914 -312.91657)
		(width 0.381)
		(layer "F.Cu")
		(net "GND")
	)
	(segment
		(start 98.482912 -228.1809)
		(end 98.483166 -228.180646)
		(width 0.2032)
		(layer "F.Cu")
		(net "GND")
	)
	(segment
		(start 334.205834 -224.925382)
		(end 334.205834 -224.389442)
		(width 0.254)
		(layer "F.Cu")
		(net "GND")
	)
	(segment
		(start 59.626246 -208.366614)
		(end 60.947046 -208.366614)
		(width 0.381)
		(layer "F.Cu")
		(net "GND")
	)
	(segment
		(start 106.001312 -216.250774)
		(end 106.001566 -216.25052)
		(width 0.254)
		(layer "F.Cu")
		(net "GND")
	)
	(segment
		(start 19.784314 -272.966688)
		(end 20.889214 -272.966688)
		(width 0.381)
		(layer "F.Cu")
		(net "GND")
	)
	(segment
		(start 328.625708 -41.401746)
		(end 329.165966 -41.401746)
		(width 0.2032)
		(layer "F.Cu")
		(net "GND")
	)
	(segment
		(start 305.443382 -196.466714)
		(end 306.548282 -196.466714)
		(width 0.381)
		(layer "F.Cu")
		(net "GND")
	)
	(segment
		(start 336.665316 -276.986492)
		(end 336.195162 -276.708616)
		(width 0.254)
		(layer "F.Cu")
		(net "GND")
	)
	(segment
		(start 25.10155 -183.33974)
		(end 25.10155 -182.59552)
		(width 0.3556)
		(layer "F.Cu")
		(net "GND")
	)
	(segment
		(start 308.887114 -236.416596)
		(end 310.207914 -236.416596)
		(width 0.381)
		(layer "F.Cu")
		(net "GND")
	)
	(segment
		(start 463.82305 -383.010664)
		(end 463.150204 -383.010664)
		(width 0.3556)
		(layer "F.Cu")
		(net "GND")
	)
	(segment
		(start 368.50828 -230.622348)
		(end 368.50828 -230.086662)
		(width 0.2032)
		(layer "F.Cu")
		(net "GND")
	)
	(segment
		(start 56.182514 -275.516594)
		(end 57.503314 -275.516594)
		(width 0.381)
		(layer "F.Cu")
		(net "GND")
	)
	(segment
		(start 44.754546 -250.016772)
		(end 45.859446 -250.016772)
		(width 0.381)
		(layer "F.Cu")
		(net "GND")
	)
	(segment
		(start 49.666906 -11.26998)
		(end 49.666906 -10.16508)
		(width 0.3556)
		(layer "F.Cu")
		(net "GND")
	)
	(segment
		(start 409.748482 -264.466578)
		(end 410.853382 -264.466578)
		(width 0.381)
		(layer "F.Cu")
		(net "GND")
	)
	(segment
		(start 48.638714 -219.41663)
		(end 49.959514 -219.41663)
		(width 0.381)
		(layer "F.Cu")
		(net "GND")
	)
	(segment
		(start 7.035546 -306.116736)
		(end 8.140446 -306.116736)
		(width 0.381)
		(layer "F.Cu")
		(net "GND")
	)
	(segment
		(start 424.836082 -222.816674)
		(end 425.940982 -222.816674)
		(width 0.381)
		(layer "F.Cu")
		(net "GND")
	)
	(segment
		(start 281.707082 -277.216616)
		(end 282.811982 -277.216616)
		(width 0.381)
		(layer "F.Cu")
		(net "GND")
	)
	(segment
		(start 336.085434 -248.806208)
		(end 336.085434 -249.342148)
		(width 0.2032)
		(layer "F.Cu")
		(net "GND")
	)
	(segment
		(start 378.846334 -238.761524)
		(end 378.84608 -238.76127)
		(width 0.2032)
		(layer "F.Cu")
		(net "GND")
	)
	(segment
		(start 296.794682 -282.316682)
		(end 297.899582 -282.316682)
		(width 0.381)
		(layer "F.Cu")
		(net "GND")
	)
	(segment
		(start 129.606294 -253.383796)
		(end 129.606294 -253.919736)
		(width 0.2032)
		(layer "F.Cu")
		(net "GND")
	)
	(segment
		(start 433.484782 -196.466714)
		(end 434.589682 -196.466714)
		(width 0.381)
		(layer "F.Cu")
		(net "GND")
	)
	(segment
		(start 89.554812 -230.622348)
		(end 89.554812 -230.086662)
		(width 0.2032)
		(layer "F.Cu")
		(net "GND")
	)
	(segment
		(start 300.238414 -317.166752)
		(end 301.343314 -317.166752)
		(width 0.381)
		(layer "F.Cu")
		(net "GND")
	)
	(segment
		(start 29.666946 -210.916774)
		(end 30.771846 -210.916774)
		(width 0.381)
		(layer "F.Cu")
		(net "GND")
	)
	(segment
		(start 383.07518 -228.1809)
		(end 383.075434 -228.180646)
		(width 0.2032)
		(layer "F.Cu")
		(net "GND")
	)
	(segment
		(start 334.205834 -249.342148)
		(end 334.205834 -248.806208)
		(width 0.2032)
		(layer "F.Cu")
		(net "GND")
	)
	(segment
		(start 91.074494 -261.522718)
		(end 91.074494 -262.058658)
		(width 0.2032)
		(layer "F.Cu")
		(net "GND")
	)
	(segment
		(start 422.945814 -307.816758)
		(end 421.840914 -307.816758)
		(width 0.381)
		(layer "F.Cu")
		(net "GND")
	)
	(segment
		(start 159.42183 -59.527948)
		(end 159.42183 -60.162948)
		(width 0.3556)
		(layer "F.Cu")
		(net "GND")
	)
	(segment
		(start 325.95312 -347.941392)
		(end 325.95312 -348.564454)
		(width 0.3556)
		(layer "F.Cu")
		(net "GND")
	)
	(segment
		(start 405.648414 -258.516628)
		(end 406.753314 -258.516628)
		(width 0.381)
		(layer "F.Cu")
		(net "GND")
	)
	(segment
		(start 289.250882 -308.666642)
		(end 290.355782 -308.666642)
		(width 0.381)
		(layer "F.Cu")
		(net "GND")
	)
	(segment
		(start 140.598144 -78.111858)
		(end 140.209524 -78.500478)
		(width 0.3556)
		(layer "F.Cu")
		(net "GND")
	)
	(segment
		(start 381.305562 -281.591512)
		(end 381.305816 -281.591766)
		(width 0.254)
		(layer "F.Cu")
		(net "GND")
	)
	(segment
		(start 457.221082 -204.116686)
		(end 456.116182 -204.116686)
		(width 0.381)
		(layer "F.Cu")
		(net "GND")
	)
	(segment
		(start 94.254066 -238.761524)
		(end 94.253812 -238.76127)
		(width 0.2032)
		(layer "F.Cu")
		(net "GND")
	)
	(segment
		(start 370.388134 -233.87812)
		(end 370.38788 -233.877866)
		(width 0.254)
		(layer "F.Cu")
		(net "GND")
	)
	(segment
		(start 448.572382 -261.066788)
		(end 447.467482 -261.066788)
		(width 0.381)
		(layer "F.Cu")
		(net "GND")
	)
	(segment
		(start 39.420546 -216.016586)
		(end 38.315646 -216.016586)
		(width 0.381)
		(layer "F.Cu")
		(net "GND")
	)
	(segment
		(start 438.277 -96.757998)
		(end 438.277 -97.450148)
		(width 0.3556)
		(layer "F.Cu")
		(net "GND")
	)
	(segment
		(start 18.679414 -232.166668)
		(end 19.784314 -232.166668)
		(width 0.381)
		(layer "F.Cu")
		(net "GND")
	)
	(segment
		(start 124.437648 -281.869896)
		(end 124.437394 -282.405836)
		(width 0.2032)
		(layer "F.Cu")
		(net "GND")
	)
	(segment
		(start 281.707082 -194.766692)
		(end 282.811982 -194.766692)
		(width 0.381)
		(layer "F.Cu")
		(net "GND")
	)
	(segment
		(start 463.659982 -194.766692)
		(end 464.764882 -194.766692)
		(width 0.381)
		(layer "F.Cu")
		(net "GND")
	)
	(segment
		(start 97.183448 -287.288986)
		(end 97.183194 -287.28924)
		(width 0.254)
		(layer "F.Cu")
		(net "GND")
	)
	(segment
		(start 15.684246 -201.56678)
		(end 16.789146 -201.56678)
		(width 0.381)
		(layer "F.Cu")
		(net "GND")
	)
	(segment
		(start 328.244962 -41.947084)
		(end 328.187812 -42.004234)
		(width 0.2032)
		(layer "F.Cu")
		(net "GND")
	)
	(segment
		(start 34.871914 -288.266632)
		(end 33.767014 -288.266632)
		(width 0.381)
		(layer "F.Cu")
		(net "GND")
	)
	(segment
		(start 45.859446 -242.3668)
		(end 46.964346 -242.3668)
		(width 0.381)
		(layer "F.Cu")
		(net "GND")
	)
	(segment
		(start 346.893134 -220.855794)
		(end 346.893134 -220.319854)
		(width 0.2032)
		(layer "F.Cu")
		(net "GND")
	)
	(segment
		(start 15.684246 -289.11677)
		(end 16.789146 -289.11677)
		(width 0.381)
		(layer "F.Cu")
		(net "GND")
	)
	(segment
		(start 314.685172 -53.228748)
		(end 314.710572 -53.203348)
		(width 0.381)
		(layer "F.Cu")
		(net "GND")
	)
	(segment
		(start 459.559914 -292.516814)
		(end 460.664814 -292.516814)
		(width 0.381)
		(layer "F.Cu")
		(net "GND")
	)
	(segment
		(start 184.439814 -210.066636)
		(end 185.544714 -210.066636)
		(width 0.381)
		(layer "F.Cu")
		(net "GND")
	)
	(segment
		(start 77.509878 -345.474036)
		(end 77.683106 -345.055952)
		(width 0.1778)
		(layer "F.Cu")
		(net "GND")
	)
	(segment
		(start 63.942214 -230.466646)
		(end 65.047114 -230.466646)
		(width 0.381)
		(layer "F.Cu")
		(net "GND")
	)
	(segment
		(start 210.514946 -227.066602)
		(end 211.619846 -227.066602)
		(width 0.381)
		(layer "F.Cu")
		(net "GND")
	)
	(segment
		(start 200.632314 -232.166668)
		(end 201.737214 -232.166668)
		(width 0.381)
		(layer "F.Cu")
		(net "GND")
	)
	(segment
		(start 347.214698 -57.954926)
		(end 346.799662 -57.454546)
		(width 0.2032)
		(layer "F.Cu")
		(net "GND")
	)
	(segment
		(start 173.900846 -278.066754)
		(end 175.005746 -278.066754)
		(width 0.381)
		(layer "F.Cu")
		(net "GND")
	)
	(segment
		(start 449.677282 -269.566644)
		(end 448.572382 -269.566644)
		(width 0.381)
		(layer "F.Cu")
		(net "GND")
	)
	(segment
		(start 308.887114 -195.616576)
		(end 309.992014 -195.616576)
		(width 0.381)
		(layer "F.Cu")
		(net "GND")
	)
	(segment
		(start 459.559914 -220.266768)
		(end 460.664814 -220.266768)
		(width 0.381)
		(layer "F.Cu")
		(net "GND")
	)
	(segment
		(start 352.171762 -279.428194)
		(end 352.171762 -279.96388)
		(width 0.2032)
		(layer "F.Cu")
		(net "GND")
	)
	(segment
		(start 158.813246 -290.816792)
		(end 159.918146 -290.816792)
		(width 0.381)
		(layer "F.Cu")
		(net "GND")
	)
	(segment
		(start 290.355782 -280.61666)
		(end 291.460682 -280.61666)
		(width 0.381)
		(layer "F.Cu")
		(net "GND")
	)
	(segment
		(start 85.905594 -285.661354)
		(end 85.905594 -285.125414)
		(width 0.2032)
		(layer "F.Cu")
		(net "GND")
	)
	(segment
		(start 126.786894 -282.683966)
		(end 126.786894 -283.219906)
		(width 0.254)
		(layer "F.Cu")
		(net "GND")
	)
	(segment
		(start 65.047114 -245.76659)
		(end 66.152014 -245.76659)
		(width 0.381)
		(layer "F.Cu")
		(net "GND")
	)
	(segment
		(start 266.619482 -306.96662)
		(end 267.724382 -306.96662)
		(width 0.381)
		(layer "F.Cu")
		(net "GND")
	)
	(segment
		(start 325.772272 -54.031388)
		(end 325.850758 -53.952902)
		(width 0.2032)
		(layer "F.Cu")
		(net "GND")
	)
	(segment
		(start 448.572382 -295.916604)
		(end 447.467482 -295.916604)
		(width 0.381)
		(layer "F.Cu")
		(net "GND")
	)
	(segment
		(start 441.028582 -301.01667)
		(end 442.133482 -301.01667)
		(width 0.381)
		(layer "F.Cu")
		(net "GND")
	)
	(segment
		(start 374.257316 -259.093462)
		(end 374.257062 -259.616956)
		(width 0.2032)
		(layer "F.Cu")
		(net "GND")
	)
	(segment
		(start 272.273014 -268.71676)
		(end 271.168114 -268.71676)
		(width 0.381)
		(layer "F.Cu")
		(net "GND")
	)
	(segment
		(start 107.3404 -408.8892)
		(end 106.893614 -409.335986)
		(width 0.3556)
		(layer "F.Cu")
		(net "GND")
	)
	(segment
		(start 339.374734 -243.108988)
		(end 339.374734 -243.644928)
		(width 0.2032)
		(layer "F.Cu")
		(net "GND")
	)
	(segment
		(start 277.607014 -238.966756)
		(end 278.711914 -238.966756)
		(width 0.381)
		(layer "F.Cu")
		(net "GND")
	)
	(segment
		(start 86.375494 -266.405868)
		(end 87.315294 -266.941808)
		(width 0.2032)
		(layer "F.Cu")
		(net "GND")
	)
	(segment
		(start 180.339746 -221.96679)
		(end 181.444646 -221.96679)
		(width 0.381)
		(layer "F.Cu")
		(net "GND")
	)
	(segment
		(start 14.445996 -107.083352)
		(end 14.486128 -107.123484)
		(width 0.3556)
		(layer "F.Cu")
		(net "GND")
	)
	(segment
		(start 375.087134 -245.27256)
		(end 375.087134 -244.73662)
		(width 0.2032)
		(layer "F.Cu")
		(net "GND")
	)
	(segment
		(start 7.035546 -265.316716)
		(end 8.140446 -265.316716)
		(width 0.381)
		(layer "F.Cu")
		(net "GND")
	)
	(segment
		(start 204.076046 -295.06672)
		(end 205.180946 -295.06672)
		(width 0.381)
		(layer "F.Cu")
		(net "GND")
	)
	(segment
		(start 113.519966 -234.691936)
		(end 113.519966 -234.15625)
		(width 0.254)
		(layer "F.Cu")
		(net "GND")
	)
	(segment
		(start 375.557034 -234.691936)
		(end 375.557034 -234.15625)
		(width 0.2032)
		(layer "F.Cu")
		(net "GND")
	)
	(segment
		(start 87.785194 -255.825498)
		(end 87.785194 -256.361438)
		(width 0.254)
		(layer "F.Cu")
		(net "GND")
	)
	(segment
		(start 358.170734 -235.506006)
		(end 358.170734 -234.970066)
		(width 0.2032)
		(layer "F.Cu")
		(net "GND")
	)
	(segment
		(start 178.000914 -306.96662)
		(end 179.105814 -306.96662)
		(width 0.381)
		(layer "F.Cu")
		(net "GND")
	)
	(segment
		(start 308.887114 -281.466798)
		(end 309.992014 -281.466798)
		(width 0.381)
		(layer "F.Cu")
		(net "GND")
	)
	(segment
		(start 44.754546 -233.016806)
		(end 45.859446 -233.016806)
		(width 0.381)
		(layer "F.Cu")
		(net "GND")
	)
	(segment
		(start 383.655062 -259.081016)
		(end 383.655062 -259.093462)
		(width 0.2032)
		(layer "F.Cu")
		(net "GND")
	)
	(segment
		(start 427.490128 -344.017346)
		(end 428.430436 -344.017346)
		(width 0.508)
		(layer "F.Cu")
		(net "GND")
	)
	(segment
		(start 340.894162 -279.428194)
		(end 340.894162 -279.96388)
		(width 0.254)
		(layer "F.Cu")
		(net "GND")
	)
	(segment
		(start 90.964512 -236.319822)
		(end 90.964512 -235.783882)
		(width 0.2032)
		(layer "F.Cu")
		(net "GND")
	)
	(segment
		(start 352.06178 -231.436418)
		(end 352.062034 -231.436164)
		(width 0.2032)
		(layer "F.Cu")
		(net "GND")
	)
	(segment
		(start 122.558048 -280.242264)
		(end 122.557794 -280.778204)
		(width 0.2032)
		(layer "F.Cu")
		(net "GND")
	)
	(segment
		(start 134.195566 -230.900478)
		(end 134.195566 -231.436418)
		(width 0.2032)
		(layer "F.Cu")
		(net "GND")
	)
	(segment
		(start 155.27274 -67.633088)
		(end 154.61488 -68.290948)
		(width 0.3556)
		(layer "F.Cu")
		(net "GND")
	)
	(segment
		(start 362.399834 -220.041978)
		(end 362.399834 -219.506038)
		(width 0.254)
		(layer "F.Cu")
		(net "GND")
	)
	(segment
		(start 374.257316 -254.197612)
		(end 374.257316 -254.733552)
		(width 0.2032)
		(layer "F.Cu")
		(net "GND")
	)
	(segment
		(start 92.954094 -286.47517)
		(end 92.954348 -286.475424)
		(width 0.2032)
		(layer "F.Cu")
		(net "GND")
	)
	(segment
		(start 263.624314 -220.266768)
		(end 264.729214 -220.266768)
		(width 0.381)
		(layer "F.Cu")
		(net "GND")
	)
	(segment
		(start 384.95478 -247.714262)
		(end 384.955034 -247.714008)
		(width 0.2032)
		(layer "F.Cu")
		(net "GND")
	)
	(segment
		(start 436.928514 -210.916774)
		(end 438.033414 -210.916774)
		(width 0.381)
		(layer "F.Cu")
		(net "GND")
	)
	(segment
		(start 27.328114 -299.316648)
		(end 28.433014 -299.316648)
		(width 0.381)
		(layer "F.Cu")
		(net "GND")
	)
	(segment
		(start 45.859446 -206.666592)
		(end 46.964346 -206.666592)
		(width 0.381)
		(layer "F.Cu")
		(net "GND")
	)
	(segment
		(start 254.975614 -298.466764)
		(end 256.080514 -298.466764)
		(width 0.381)
		(layer "F.Cu")
		(net "GND")
	)
	(segment
		(start 89.555066 -233.87812)
		(end 89.554812 -233.877866)
		(width 0.2032)
		(layer "F.Cu")
		(net "GND")
	)
	(segment
		(start 196.532246 -212.616796)
		(end 197.637146 -212.616796)
		(width 0.381)
		(layer "F.Cu")
		(net "GND")
	)
	(segment
		(start 340.562946 -45.160946)
		(end 340.439248 -45.037248)
		(width 0.2032)
		(layer "F.Cu")
		(net "GND")
	)
	(segment
		(start 380.835662 -280.242518)
		(end 380.835662 -280.778204)
		(width 0.254)
		(layer "F.Cu")
		(net "GND")
	)
	(segment
		(start 311.882282 -249.166634)
		(end 312.987182 -249.166634)
		(width 0.381)
		(layer "F.Cu")
		(net "GND")
	)
	(segment
		(start 135.714994 -286.7533)
		(end 135.714994 -287.28924)
		(width 0.2032)
		(layer "F.Cu")
		(net "GND")
	)
	(segment
		(start 359.59796 -402.194014)
		(end 360.233214 -402.194014)
		(width 0.3556)
		(layer "F.Cu")
		(net "GND")
	)
	(segment
		(start 104.701848 -283.497782)
		(end 104.701848 -284.033468)
		(width 0.254)
		(layer "F.Cu")
		(net "GND")
	)
	(segment
		(start 340.562946 -48.920146)
		(end 340.290658 -48.450246)
		(width 0.2032)
		(layer "F.Cu")
		(net "GND")
	)
	(segment
		(start 385.534662 -273.730974)
		(end 385.093464 -273.475958)
		(width 0.254)
		(layer "F.Cu")
		(net "GND")
	)
	(segment
		(start 56.182514 -288.266632)
		(end 57.503314 -288.266632)
		(width 0.381)
		(layer "F.Cu")
		(net "GND")
	)
	(segment
		(start 378.956316 -255.825498)
		(end 378.956316 -256.361184)
		(width 0.254)
		(layer "F.Cu")
		(net "GND")
	)
	(segment
		(start 52.298346 -272.116804)
		(end 53.403246 -272.116804)
		(width 0.381)
		(layer "F.Cu")
		(net "GND")
	)
	(segment
		(start 29.666946 -238.966756)
		(end 30.771846 -238.966756)
		(width 0.381)
		(layer "F.Cu")
		(net "GND")
	)
	(segment
		(start 92.014294 -282.683966)
		(end 92.014294 -283.219906)
		(width 0.2032)
		(layer "F.Cu")
		(net "GND")
	)
	(segment
		(start 353.581716 -268.84757)
		(end 353.581462 -268.847824)
		(width 0.254)
		(layer "F.Cu")
		(net "GND")
	)
	(segment
		(start 139.05103 -269.757398)
		(end 139.553188 -270.259556)
		(width 0.254)
		(layer "F.Cu")
		(net "GND")
	)
	(segment
		(start 186.955684 -104.975406)
		(end 187.355734 -104.575356)
		(width 0.3556)
		(layer "F.Cu")
		(net "GND")
	)
	(segment
		(start 297.843702 -423.954448)
		(end 298.396406 -424.507152)
		(width 0.3556)
		(layer "F.Cu")
		(net "GND")
	)
	(segment
		(start 120.098312 -226.017582)
		(end 120.098566 -226.017328)
		(width 0.254)
		(layer "F.Cu")
		(net "GND")
	)
	(segment
		(start 100.362512 -226.553268)
		(end 100.362512 -226.017582)
		(width 0.254)
		(layer "F.Cu")
		(net "GND")
	)
	(segment
		(start 98.123248 -268.84757)
		(end 98.123248 -269.38351)
		(width 0.2032)
		(layer "F.Cu")
		(net "GND")
	)
	(segment
		(start 383.185162 -274.54479)
		(end 383.185162 -275.08073)
		(width 0.2032)
		(layer "F.Cu")
		(net "GND")
	)
	(segment
		(start 53.403246 -273.816572)
		(end 54.724046 -273.816572)
		(width 0.381)
		(layer "F.Cu")
		(net "GND")
	)
	(segment
		(start 160.221168 -204.96657)
		(end 158.813246 -204.96657)
		(width 0.381)
		(layer "F.Cu")
		(net "GND")
	)
	(segment
		(start 304.1396 -418.7063)
		(end 304.1396 -418.069268)
		(width 0.3556)
		(layer "F.Cu")
		(net "GND")
	)
	(segment
		(start 161.808414 -306.96662)
		(end 162.913314 -306.96662)
		(width 0.381)
		(layer "F.Cu")
		(net "GND")
	)
	(segment
		(start 419.502082 -205.816708)
		(end 418.397182 -205.816708)
		(width 0.381)
		(layer "F.Cu")
		(net "GND")
	)
	(segment
		(start 418.397182 -282.316682)
		(end 417.292282 -282.316682)
		(width 0.381)
		(layer "F.Cu")
		(net "GND")
	)
	(segment
		(start 200.632314 -226.216718)
		(end 201.737214 -226.216718)
		(width 0.381)
		(layer "F.Cu")
		(net "GND")
	)
	(segment
		(start 367.09858 -216.78646)
		(end 367.09858 -216.250774)
		(width 0.254)
		(layer "F.Cu")
		(net "GND")
	)
	(segment
		(start 449.677282 -275.516594)
		(end 448.572382 -275.516594)
		(width 0.381)
		(layer "F.Cu")
		(net "GND")
	)
	(segment
		(start 378.846334 -243.644928)
		(end 378.84608 -243.644674)
		(width 0.2032)
		(layer "F.Cu")
		(net "GND")
	)
	(segment
		(start 129.966212 -235.505752)
		(end 129.966212 -234.970066)
		(width 0.2032)
		(layer "F.Cu")
		(net "GND")
	)
	(segment
		(start 44.754546 -311.216802)
		(end 45.859446 -311.216802)
		(width 0.381)
		(layer "F.Cu")
		(net "GND")
	)
	(segment
		(start 176.896014 -291.666676)
		(end 178.000914 -291.666676)
		(width 0.381)
		(layer "F.Cu")
		(net "GND")
	)
	(segment
		(start 383.07518 -218.414346)
		(end 383.07518 -217.878406)
		(width 0.2032)
		(layer "F.Cu")
		(net "GND")
	)
	(segment
		(start 204.076046 -265.316716)
		(end 205.180946 -265.316716)
		(width 0.381)
		(layer "F.Cu")
		(net "GND")
	)
	(segment
		(start 48.638714 -210.066636)
		(end 49.959514 -210.066636)
		(width 0.381)
		(layer "F.Cu")
		(net "GND")
	)
	(segment
		(start 361.45978 -243.923058)
		(end 361.460034 -243.922804)
		(width 0.254)
		(layer "F.Cu")
		(net "GND")
	)
	(segment
		(start 60.947046 -263.616694)
		(end 62.051946 -263.616694)
		(width 0.381)
		(layer "F.Cu")
		(net "GND")
	)
	(segment
		(start 333.510382 -44.221146)
		(end 334.05064 -44.221146)
		(width 0.2032)
		(layer "F.Cu")
		(net "GND")
	)
	(segment
		(start 263.624314 -251.716794)
		(end 264.729214 -251.716794)
		(width 0.381)
		(layer "F.Cu")
		(net "GND")
	)
	(segment
		(start 331.608176 -48.450246)
		(end 331.880718 -48.920146)
		(width 0.2032)
		(layer "F.Cu")
		(net "GND")
	)
	(segment
		(start 348.141544 -57.732168)
		(end 347.864176 -57.732168)
		(width 0.2032)
		(layer "F.Cu")
		(net "GND")
	)
	(segment
		(start 311.666382 -271.266666)
		(end 312.987182 -271.266666)
		(width 0.381)
		(layer "F.Cu")
		(net "GND")
	)
	(segment
		(start 305.443382 -261.066788)
		(end 306.548282 -261.066788)
		(width 0.381)
		(layer "F.Cu")
		(net "GND")
	)
	(segment
		(start 124.437648 -278.614378)
		(end 124.437648 -279.150064)
		(width 0.254)
		(layer "F.Cu")
		(net "GND")
	)
	(segment
		(start 364.279434 -229.808532)
		(end 364.279434 -229.272846)
		(width 0.254)
		(layer "F.Cu")
		(net "GND")
	)
	(segment
		(start 427.045882 -310.366664)
		(end 425.940982 -310.366664)
		(width 0.381)
		(layer "F.Cu")
		(net "GND")
	)
	(segment
		(start 394.899896 -57.03062)
		(end 394.899896 -60.174886)
		(width 0.3556)
		(layer "F.Cu")
		(net "GND")
	)
	(segment
		(start 411.958282 -244.066568)
		(end 410.853382 -244.066568)
		(width 0.381)
		(layer "F.Cu")
		(net "GND")
	)
	(segment
		(start 44.754546 -258.516628)
		(end 45.859446 -258.516628)
		(width 0.381)
		(layer "F.Cu")
		(net "GND")
	)
	(segment
		(start 449.677282 -258.516628)
		(end 448.572382 -258.516628)
		(width 0.381)
		(layer "F.Cu")
		(net "GND")
	)
	(segment
		(start 263.624314 -267.016738)
		(end 264.729214 -267.016738)
		(width 0.381)
		(layer "F.Cu")
		(net "GND")
	)
	(segment
		(start 23.228046 -306.116736)
		(end 24.332946 -306.116736)
		(width 0.381)
		(layer "F.Cu")
		(net "GND")
	)
	(segment
		(start 23.228046 -298.466764)
		(end 24.332946 -298.466764)
		(width 0.381)
		(layer "F.Cu")
		(net "GND")
	)
	(segment
		(start 129.74701 -17.655032)
		(end 129.74701 -16.550132)
		(width 0.3556)
		(layer "F.Cu")
		(net "GND")
	)
	(segment
		(start 132.895848 -287.288986)
		(end 132.895594 -287.28924)
		(width 0.254)
		(layer "F.Cu")
		(net "GND")
	)
	(segment
		(start 186.649614 -305.266598)
		(end 185.544714 -305.266598)
		(width 0.381)
		(layer "F.Cu")
		(net "GND")
	)
	(segment
		(start 358.280716 -257.988816)
		(end 358.280462 -257.98907)
		(width 0.254)
		(layer "F.Cu")
		(net "GND")
	)
	(segment
		(start 337.604862 -272.103342)
		(end 337.604862 -272.639282)
		(width 0.2032)
		(layer "F.Cu")
		(net "GND")
	)
	(segment
		(start 14.579346 -234.716574)
		(end 15.684246 -234.716574)
		(width 0.381)
		(layer "F.Cu")
		(net "GND")
	)
	(segment
		(start 63.942214 -244.066568)
		(end 65.047114 -244.066568)
		(width 0.381)
		(layer "F.Cu")
		(net "GND")
	)
	(segment
		(start 88.725248 -257.45313)
		(end 88.725248 -257.988816)
		(width 0.2032)
		(layer "F.Cu")
		(net "GND")
	)
	(segment
		(start 384.124962 -282.683966)
		(end 384.124962 -283.219906)
		(width 0.254)
		(layer "F.Cu")
		(net "GND")
	)
	(segment
		(start 262.519414 -258.516628)
		(end 263.624314 -258.516628)
		(width 0.381)
		(layer "F.Cu")
		(net "GND")
	)
	(segment
		(start 19.12112 -168.509188)
		(end 19.707352 -167.922956)
		(width 0.3556)
		(layer "F.Cu")
		(net "GND")
	)
	(segment
		(start 289.250882 -261.066788)
		(end 290.355782 -261.066788)
		(width 0.381)
		(layer "F.Cu")
		(net "GND")
	)
	(segment
		(start 300.238414 -285.716726)
		(end 301.343314 -285.716726)
		(width 0.381)
		(layer "F.Cu")
		(net "GND")
	)
	(segment
		(start 23.228046 -236.416596)
		(end 24.332946 -236.416596)
		(width 0.381)
		(layer "F.Cu")
		(net "GND")
	)
	(segment
		(start 427.045882 -289.966654)
		(end 425.940982 -289.966654)
		(width 0.381)
		(layer "F.Cu")
		(net "GND")
	)
	(segment
		(start 138.894312 -241.203226)
		(end 139.516612 -241.203226)
		(width 0.254)
		(layer "F.Cu")
		(net "GND")
	)
	(segment
		(start 294.904414 -296.766742)
		(end 293.799514 -296.766742)
		(width 0.381)
		(layer "F.Cu")
		(net "GND")
	)
	(segment
		(start 42.415714 -280.61666)
		(end 41.310814 -280.61666)
		(width 0.381)
		(layer "F.Cu")
		(net "GND")
	)
	(segment
		(start 126.317248 -260.708902)
		(end 126.317248 -261.244588)
		(width 0.2032)
		(layer "F.Cu")
		(net "GND")
	)
	(segment
		(start 293.799514 -246.616728)
		(end 292.694614 -246.616728)
		(width 0.381)
		(layer "F.Cu")
		(net "GND")
	)
	(segment
		(start 358.280716 -267.755624)
		(end 358.280462 -267.755878)
		(width 0.254)
		(layer "F.Cu")
		(net "GND")
	)
	(segment
		(start 122.557794 -264.500106)
		(end 122.557794 -264.50036)
		(width 0.2032)
		(layer "F.Cu")
		(net "GND")
	)
	(segment
		(start 29.666946 -197.316598)
		(end 30.771846 -197.316598)
		(width 0.381)
		(layer "F.Cu")
		(net "GND")
	)
	(segment
		(start 312.987182 -269.566644)
		(end 314.092082 -269.566644)
		(width 0.381)
		(layer "F.Cu")
		(net "GND")
	)
	(segment
		(start 51.064414 -275.516594)
		(end 49.959514 -275.516594)
		(width 0.381)
		(layer "F.Cu")
		(net "GND")
	)
	(segment
		(start 193.088514 -289.966654)
		(end 194.193414 -289.966654)
		(width 0.381)
		(layer "F.Cu")
		(net "GND")
	)
	(segment
		(start 26.223214 -291.666676)
		(end 27.328114 -291.666676)
		(width 0.381)
		(layer "F.Cu")
		(net "GND")
	)
	(segment
		(start 338.90077 -58.43524)
		(end 338.90077 -57.605168)
		(width 0.254)
		(layer "F.Cu")
		(net "GND")
	)
	(segment
		(start 452.016114 -311.216802)
		(end 450.911214 -311.216802)
		(width 0.381)
		(layer "F.Cu")
		(net "GND")
	)
	(segment
		(start 357.69804 -403.493986)
		(end 357.69804 -403.94636)
		(width 0.3556)
		(layer "F.Cu")
		(net "GND")
	)
	(segment
		(start 170.457114 -271.266666)
		(end 171.562014 -271.266666)
		(width 0.381)
		(layer "F.Cu")
		(net "GND")
	)
	(segment
		(start 433.484782 -306.96662)
		(end 434.589682 -306.96662)
		(width 0.381)
		(layer "F.Cu")
		(net "GND")
	)
	(segment
		(start 15.684246 -281.466798)
		(end 16.789146 -281.466798)
		(width 0.381)
		(layer "F.Cu")
		(net "GND")
	)
	(segment
		(start 281.707082 -308.666642)
		(end 282.811982 -308.666642)
		(width 0.381)
		(layer "F.Cu")
		(net "GND")
	)
	(segment
		(start 292.694614 -248.31675)
		(end 293.799514 -248.31675)
		(width 0.381)
		(layer "F.Cu")
		(net "GND")
	)
	(segment
		(start 441.028582 -205.816708)
		(end 442.133482 -205.816708)
		(width 0.381)
		(layer "F.Cu")
		(net "GND")
	)
	(segment
		(start 297.899582 -262.76681)
		(end 299.004482 -262.76681)
		(width 0.381)
		(layer "F.Cu")
		(net "GND")
	)
	(segment
		(start 104.121966 -233.06405)
		(end 104.121966 -232.528364)
		(width 0.254)
		(layer "F.Cu")
		(net "GND")
	)
	(segment
		(start 382.135634 -229.808786)
		(end 382.135634 -229.272846)
		(width 0.2032)
		(layer "F.Cu")
		(net "GND")
	)
	(segment
		(start 49.959514 -288.266632)
		(end 51.064414 -288.266632)
		(width 0.381)
		(layer "F.Cu")
		(net "GND")
	)
	(segment
		(start 53.403246 -281.466798)
		(end 54.508146 -281.466798)
		(width 0.381)
		(layer "F.Cu")
		(net "GND")
	)
	(segment
		(start 380.25578 -219.506292)
		(end 380.256034 -219.506038)
		(width 0.254)
		(layer "F.Cu")
		(net "GND")
	)
	(segment
		(start 423.804842 -380.329948)
		(end 423.195242 -380.329948)
		(width 0.3556)
		(layer "F.Cu")
		(net "GND")
	)
	(segment
		(start 100.942394 -268.847824)
		(end 100.942394 -269.38351)
		(width 0.2032)
		(layer "F.Cu")
		(net "GND")
	)
	(segment
		(start 91.434412 -232.250234)
		(end 91.434412 -231.714548)
		(width 0.2032)
		(layer "F.Cu")
		(net "GND")
	)
	(segment
		(start 289.250882 -299.316648)
		(end 290.355782 -299.316648)
		(width 0.381)
		(layer "F.Cu")
		(net "GND")
	)
	(segment
		(start 134.305294 -266.405868)
		(end 134.305548 -266.941808)
		(width 0.2032)
		(layer "F.Cu")
		(net "GND")
	)
	(segment
		(start 52.298346 -285.716726)
		(end 53.403246 -285.716726)
		(width 0.381)
		(layer "F.Cu")
		(net "GND")
	)
	(segment
		(start 119.158512 -226.017582)
		(end 119.158766 -226.017328)
		(width 0.254)
		(layer "F.Cu")
		(net "GND")
	)
	(segment
		(start 104.121712 -220.041978)
		(end 104.121966 -220.041724)
		(width 0.254)
		(layer "F.Cu")
		(net "GND")
	)
	(segment
		(start 414.297114 -317.166752)
		(end 415.402014 -317.166752)
		(width 0.381)
		(layer "F.Cu")
		(net "GND")
	)
	(segment
		(start 59.626246 -276.366732)
		(end 60.947046 -276.366732)
		(width 0.381)
		(layer "F.Cu")
		(net "GND")
	)
	(segment
		(start 189.25032 -426.303948)
		(end 188.63437 -426.303948)
		(width 0.3556)
		(layer "F.Cu")
		(net "GND")
	)
	(segment
		(start 170.457114 -226.216718)
		(end 169.352214 -226.216718)
		(width 0.381)
		(layer "F.Cu")
		(net "GND")
	)
	(segment
		(start 271.168114 -313.766708)
		(end 270.063214 -313.766708)
		(width 0.381)
		(layer "F.Cu")
		(net "GND")
	)
	(segment
		(start 109.760512 -220.041978)
		(end 109.760766 -220.041724)
		(width 0.254)
		(layer "F.Cu")
		(net "GND")
	)
	(segment
		(start 453.121014 -309.51678)
		(end 452.016114 -309.51678)
		(width 0.381)
		(layer "F.Cu")
		(net "GND")
	)
	(segment
		(start 418.397182 -272.966688)
		(end 417.063682 -272.966688)
		(width 0.381)
		(layer "F.Cu")
		(net "GND")
	)
	(segment
		(start 370.967762 -271.289272)
		(end 370.968016 -271.825212)
		(width 0.2032)
		(layer "F.Cu")
		(net "GND")
	)
	(segment
		(start 456.116182 -312.91657)
		(end 455.011282 -312.91657)
		(width 0.381)
		(layer "F.Cu")
		(net "GND")
	)
	(segment
		(start 305.443382 -271.266666)
		(end 306.548282 -271.266666)
		(width 0.381)
		(layer "F.Cu")
		(net "GND")
	)
	(segment
		(start 339.484716 -255.825498)
		(end 339.484716 -256.361184)
		(width 0.2032)
		(layer "F.Cu")
		(net "GND")
	)
	(segment
		(start 227.838 -225.288348)
		(end 227.838 -226.54133)
		(width 0.3556)
		(layer "F.Cu")
		(net "GND")
	)
	(segment
		(start 123.497848 -262.87222)
		(end 123.497594 -262.872474)
		(width 0.254)
		(layer "F.Cu")
		(net "GND")
	)
	(segment
		(start 433.484782 -308.666642)
		(end 434.589682 -308.666642)
		(width 0.381)
		(layer "F.Cu")
		(net "GND")
	)
	(segment
		(start 193.088514 -261.066788)
		(end 191.983614 -261.066788)
		(width 0.381)
		(layer "F.Cu")
		(net "GND")
	)
	(segment
		(start 415.919412 -367.0681)
		(end 415.919412 -367.104676)
		(width 0.381)
		(layer "F.Cu")
		(net "GND")
	)
	(segment
		(start 129.966466 -240.389156)
		(end 129.966212 -240.388902)
		(width 0.2032)
		(layer "F.Cu")
		(net "GND")
	)
	(segment
		(start 90.604848 -283.497782)
		(end 90.604594 -283.498036)
		(width 0.254)
		(layer "F.Cu")
		(net "GND")
	)
	(segment
		(start 340.784434 -237.947454)
		(end 340.784434 -237.411514)
		(width 0.254)
		(layer "F.Cu")
		(net "GND")
	)
	(segment
		(start 14.579346 -309.51678)
		(end 15.684246 -309.51678)
		(width 0.381)
		(layer "F.Cu")
		(net "GND")
	)
	(segment
		(start 370.498116 -263.96442)
		(end 370.498116 -264.499852)
		(width 0.2032)
		(layer "F.Cu")
		(net "GND")
	)
	(segment
		(start 27.328114 -198.166736)
		(end 28.433014 -198.166736)
		(width 0.381)
		(layer "F.Cu")
		(net "GND")
	)
	(segment
		(start 300.238414 -307.816758)
		(end 301.343314 -307.816758)
		(width 0.381)
		(layer "F.Cu")
		(net "GND")
	)
	(segment
		(start 407.658316 -236.416596)
		(end 406.753314 -236.416596)
		(width 0.381)
		(layer "F.Cu")
		(net "GND")
	)
	(segment
		(start 336.085434 -226.553268)
		(end 336.085434 -226.017328)
		(width 0.254)
		(layer "F.Cu")
		(net "GND")
	)
	(segment
		(start 39.420546 -261.916672)
		(end 38.315646 -261.916672)
		(width 0.381)
		(layer "F.Cu")
		(net "GND")
	)
	(segment
		(start 48.854614 -286.56661)
		(end 49.959514 -286.56661)
		(width 0.381)
		(layer "F.Cu")
		(net "GND")
	)
	(segment
		(start 405.648414 -276.366732)
		(end 406.753314 -276.366732)
		(width 0.381)
		(layer "F.Cu")
		(net "GND")
	)
	(segment
		(start 254.975614 -220.266768)
		(end 256.080514 -220.266768)
		(width 0.381)
		(layer "F.Cu")
		(net "GND")
	)
	(segment
		(start 361.45978 -220.041978)
		(end 361.460034 -220.041724)
		(width 0.254)
		(layer "F.Cu")
		(net "GND")
	)
	(segment
		(start 89.084912 -247.714262)
		(end 89.084912 -247.178576)
		(width 0.2032)
		(layer "F.Cu")
		(net "GND")
	)
	(segment
		(start 210.514946 -236.416596)
		(end 211.619846 -236.416596)
		(width 0.381)
		(layer "F.Cu")
		(net "GND")
	)
	(segment
		(start 286.255714 -201.56678)
		(end 287.360614 -201.56678)
		(width 0.381)
		(layer "F.Cu")
		(net "GND")
	)
	(segment
		(start 297.899582 -282.316682)
		(end 299.004482 -282.316682)
		(width 0.381)
		(layer "F.Cu")
		(net "GND")
	)
	(segment
		(start 98.122994 -266.128246)
		(end 98.122994 -265.592306)
		(width 0.254)
		(layer "F.Cu")
		(net "GND")
	)
	(segment
		(start 204.076046 -306.116736)
		(end 205.180946 -306.116736)
		(width 0.381)
		(layer "F.Cu")
		(net "GND")
	)
	(segment
		(start 30.771846 -311.216802)
		(end 31.876746 -311.216802)
		(width 0.381)
		(layer "F.Cu")
		(net "GND")
	)
	(segment
		(start 110.340648 -269.383256)
		(end 110.340394 -269.38351)
		(width 0.254)
		(layer "F.Cu")
		(net "GND")
	)
	(segment
		(start 440.211972 -32.658558)
		(end 440.211972 -31.781242)
		(width 0.254)
		(layer "F.Cu")
		(net "GND")
	)
	(segment
		(start 421.30472 -153.419048)
		(end 420.905178 -153.419048)
		(width 0.254)
		(layer "F.Cu")
		(net "GND")
	)
	(segment
		(start 173.900846 -251.716794)
		(end 172.795946 -251.716794)
		(width 0.381)
		(layer "F.Cu")
		(net "GND")
	)
	(segment
		(start 367.678716 -278.614378)
		(end 367.678462 -279.150318)
		(width 0.254)
		(layer "F.Cu")
		(net "GND")
	)
	(segment
		(start 52.082446 -311.216802)
		(end 53.403246 -311.216802)
		(width 0.381)
		(layer "F.Cu")
		(net "GND")
	)
	(segment
		(start 56.398414 -198.166736)
		(end 57.503314 -198.166736)
		(width 0.381)
		(layer "F.Cu")
		(net "GND")
	)
	(segment
		(start 369.91798 -237.947454)
		(end 369.917726 -237.9472)
		(width 0.254)
		(layer "F.Cu")
		(net "GND")
	)
	(segment
		(start 311.882282 -250.866656)
		(end 312.987182 -250.866656)
		(width 0.381)
		(layer "F.Cu")
		(net "GND")
	)
	(segment
		(start 303.834546 -436.137812)
		(end 303.834546 -436.58663)
		(width 0.3556)
		(layer "F.Cu")
		(net "GND")
	)
	(segment
		(start 456.116182 -238.116618)
		(end 455.011282 -238.116618)
		(width 0.381)
		(layer "F.Cu")
		(net "GND")
	)
	(segment
		(start 435.585616 -40.104568)
		(end 435.585616 -39.500556)
		(width 0.3556)
		(layer "F.Cu")
		(net "GND")
	)
	(segment
		(start 261.285482 -275.516594)
		(end 260.180582 -275.516594)
		(width 0.381)
		(layer "F.Cu")
		(net "GND")
	)
	(segment
		(start 181.355746 -116.175536)
		(end 181.755796 -116.575586)
		(width 0.3556)
		(layer "F.Cu")
		(net "GND")
	)
	(segment
		(start 428.279814 -227.066602)
		(end 429.384714 -227.066602)
		(width 0.381)
		(layer "F.Cu")
		(net "GND")
	)
	(segment
		(start 374.257316 -279.150064)
		(end 374.257062 -279.150318)
		(width 0.254)
		(layer "F.Cu")
		(net "GND")
	)
	(segment
		(start 117.279166 -220.041724)
		(end 117.279166 -219.506038)
		(width 0.254)
		(layer "F.Cu")
		(net "GND")
	)
	(segment
		(start 48.761904 -173.047914)
		(end 48.761904 -173.818804)
		(width 0.3556)
		(layer "F.Cu")
		(net "GND")
	)
	(segment
		(start 372.847362 -278.336248)
		(end 372.847616 -278.336502)
		(width 0.254)
		(layer "F.Cu")
		(net "GND")
	)
	(segment
		(start 63.726314 -284.866588)
		(end 65.047114 -284.866588)
		(width 0.381)
		(layer "F.Cu")
		(net "GND")
	)
	(segment
		(start 375.55678 -242.830858)
		(end 375.55678 -242.295172)
		(width 0.2032)
		(layer "F.Cu")
		(net "GND")
	)
	(segment
		(start 296.794682 -204.116686)
		(end 297.899582 -204.116686)
		(width 0.381)
		(layer "F.Cu")
		(net "GND")
	)
	(segment
		(start 34.871914 -221.116652)
		(end 35.976814 -221.116652)
		(width 0.381)
		(layer "F.Cu")
		(net "GND")
	)
	(segment
		(start 378.956316 -280.242264)
		(end 378.956062 -280.778204)
		(width 0.254)
		(layer "F.Cu")
		(net "GND")
	)
	(segment
		(start 22.600666 -176.42967)
		(end 23.392384 -176.42967)
		(width 0.254)
		(layer "F.Cu")
		(net "GND")
	)
	(segment
		(start 178.000914 -250.866656)
		(end 176.896014 -250.866656)
		(width 0.381)
		(layer "F.Cu")
		(net "GND")
	)
	(segment
		(start 181.444646 -223.666558)
		(end 182.549546 -223.666558)
		(width 0.381)
		(layer "F.Cu")
		(net "GND")
	)
	(segment
		(start 102.712266 -220.855794)
		(end 102.712266 -220.319854)
		(width 0.2032)
		(layer "F.Cu")
		(net "GND")
	)
	(segment
		(start 211.591906 -134.18312)
		(end 211.709508 -134.065518)
		(width 0.254)
		(layer "F.Cu")
		(net "GND")
	)
	(segment
		(start 44.754546 -290.816792)
		(end 45.859446 -290.816792)
		(width 0.381)
		(layer "F.Cu")
		(net "GND")
	)
	(segment
		(start 52.298346 -251.716794)
		(end 53.403246 -251.716794)
		(width 0.381)
		(layer "F.Cu")
		(net "GND")
	)
	(segment
		(start 169.149014 -275.516594)
		(end 170.457114 -275.516594)
		(width 0.381)
		(layer "F.Cu")
		(net "GND")
	)
	(segment
		(start 333.845662 -275.35886)
		(end 333.375508 -275.08073)
		(width 0.2032)
		(layer "F.Cu")
		(net "GND")
	)
	(segment
		(start 124.437648 -259.081016)
		(end 124.437648 -259.093462)
		(width 0.2032)
		(layer "F.Cu")
		(net "GND")
	)
	(segment
		(start 449.677282 -250.866656)
		(end 448.572382 -250.866656)
		(width 0.381)
		(layer "F.Cu")
		(net "GND")
	)
	(segment
		(start 277.607014 -272.116804)
		(end 278.711914 -272.116804)
		(width 0.381)
		(layer "F.Cu")
		(net "GND")
	)
	(segment
		(start 193.09588 -113.706148)
		(end 193.538094 -113.263934)
		(width 0.3556)
		(layer "F.Cu")
		(net "GND")
	)
	(segment
		(start 170.457114 -299.316648)
		(end 169.352214 -299.316648)
		(width 0.381)
		(layer "F.Cu")
		(net "GND")
	)
	(segment
		(start 121.038112 -216.250774)
		(end 121.038366 -216.25052)
		(width 0.254)
		(layer "F.Cu")
		(net "GND")
	)
	(segment
		(start 185.544714 -299.316648)
		(end 186.649614 -299.316648)
		(width 0.381)
		(layer "F.Cu")
		(net "GND")
	)
	(segment
		(start 220.36786 -50.673)
		(end 219.94495 -50.25009)
		(width 0.3556)
		(layer "F.Cu")
		(net "GND")
	)
	(segment
		(start 328.036428 -347.990922)
		(end 328.647298 -347.990922)
		(width 0.3556)
		(layer "F.Cu")
		(net "GND")
	)
	(segment
		(start 34.871914 -284.866588)
		(end 33.767014 -284.866588)
		(width 0.381)
		(layer "F.Cu")
		(net "GND")
	)
	(segment
		(start 169.297096 -354.029264)
		(end 168.902634 -353.634802)
		(width 0.2032)
		(layer "F.Cu")
		(net "GND")
	)
	(segment
		(start 124.437648 -260.708902)
		(end 124.437648 -261.244588)
		(width 0.2032)
		(layer "F.Cu")
		(net "GND")
	)
	(segment
		(start 376.966734 -217.600276)
		(end 376.966734 -217.064336)
		(width 0.254)
		(layer "F.Cu")
		(net "GND")
	)
	(segment
		(start 197.23989 -95.16491)
		(end 197.1294 -95.2754)
		(width 0.3556)
		(layer "F.Cu")
		(net "GND")
	)
	(segment
		(start 124.272294 -78.587092)
		(end 123.662694 -78.587092)
		(width 0.3556)
		(layer "F.Cu")
		(net "GND")
	)
	(segment
		(start 369.088162 -282.683966)
		(end 369.088162 -283.219906)
		(width 0.254)
		(layer "F.Cu")
		(net "GND")
	)
	(segment
		(start 339.209888 -40.931846)
		(end 339.748876 -40.931846)
		(width 0.2032)
		(layer "F.Cu")
		(net "GND")
	)
	(segment
		(start 136.655048 -280.77795)
		(end 136.654794 -280.778204)
		(width 0.254)
		(layer "F.Cu")
		(net "GND")
	)
	(segment
		(start 384.595116 -267.219938)
		(end 384.595116 -267.755624)
		(width 0.254)
		(layer "F.Cu")
		(net "GND")
	)
	(segment
		(start 366.268762 -284.311598)
		(end 366.268762 -284.847284)
		(width 0.254)
		(layer "F.Cu")
		(net "GND")
	)
	(segment
		(start 308.887114 -298.466764)
		(end 309.992014 -298.466764)
		(width 0.381)
		(layer "F.Cu")
		(net "GND")
	)
	(segment
		(start 406.753314 -210.916774)
		(end 407.858214 -210.916774)
		(width 0.381)
		(layer "F.Cu")
		(net "GND")
	)
	(segment
		(start 132.785866 -238.761524)
		(end 132.785866 -238.225584)
		(width 0.2032)
		(layer "F.Cu")
		(net "GND")
	)
	(segment
		(start 185.544714 -247.466612)
		(end 186.649614 -247.466612)
		(width 0.381)
		(layer "F.Cu")
		(net "GND")
	)
	(segment
		(start 136.184894 -282.683966)
		(end 136.184894 -283.219906)
		(width 0.254)
		(layer "F.Cu")
		(net "GND")
	)
	(segment
		(start 304.122582 -210.066636)
		(end 305.443382 -210.066636)
		(width 0.381)
		(layer "F.Cu")
		(net "GND")
	)
	(segment
		(start 254.975614 -216.016586)
		(end 256.080514 -216.016586)
		(width 0.381)
		(layer "F.Cu")
		(net "GND")
	)
	(segment
		(start 124.327412 -228.994716)
		(end 124.327412 -228.45903)
		(width 0.254)
		(layer "F.Cu")
		(net "GND")
	)
	(segment
		(start 328.187812 -43.00474)
		(end 328.244962 -42.94759)
		(width 0.2032)
		(layer "F.Cu")
		(net "GND")
	)
	(segment
		(start 271.168114 -199.01662)
		(end 270.063214 -199.01662)
		(width 0.381)
		(layer "F.Cu")
		(net "GND")
	)
	(segment
		(start 377.076716 -268.84757)
		(end 377.076462 -269.38351)
		(width 0.2032)
		(layer "F.Cu")
		(net "GND")
	)
	(segment
		(start 27.328114 -244.066568)
		(end 28.433014 -244.066568)
		(width 0.381)
		(layer "F.Cu")
		(net "GND")
	)
	(segment
		(start 65.047114 -244.066568)
		(end 66.152014 -244.066568)
		(width 0.381)
		(layer "F.Cu")
		(net "GND")
	)
	(segment
		(start 277.607014 -276.366732)
		(end 278.711914 -276.366732)
		(width 0.381)
		(layer "F.Cu")
		(net "GND")
	)
	(segment
		(start 413.192214 -272.116804)
		(end 414.297114 -272.116804)
		(width 0.381)
		(layer "F.Cu")
		(net "GND")
	)
	(segment
		(start 275.268182 -202.416664)
		(end 274.163282 -202.416664)
		(width 0.381)
		(layer "F.Cu")
		(net "GND")
	)
	(segment
		(start 256.080514 -220.266768)
		(end 257.185414 -220.266768)
		(width 0.381)
		(layer "F.Cu")
		(net "GND")
	)
	(segment
		(start 27.328114 -226.216718)
		(end 28.433014 -226.216718)
		(width 0.381)
		(layer "F.Cu")
		(net "GND")
	)
	(segment
		(start 87.205312 -247.178576)
		(end 87.205566 -247.178322)
		(width 0.2032)
		(layer "F.Cu")
		(net "GND")
	)
	(segment
		(start 431.36693 -11.26998)
		(end 431.36693 -12.37488)
		(width 0.3556)
		(layer "F.Cu")
		(net "GND")
	)
	(segment
		(start 63.942214 -286.56661)
		(end 65.047114 -286.56661)
		(width 0.381)
		(layer "F.Cu")
		(net "GND")
	)
	(segment
		(start 94.00413 -335.855056)
		(end 93.830902 -336.27314)
		(width 0.1778)
		(layer "F.Cu")
		(net "GND")
	)
	(segment
		(start 105.641648 -267.219938)
		(end 105.641394 -267.220192)
		(width 0.254)
		(layer "F.Cu")
		(net "GND")
	)
	(segment
		(start 353.94138 -216.250774)
		(end 353.941634 -216.25052)
		(width 0.254)
		(layer "F.Cu")
		(net "GND")
	)
	(segment
		(start 427.826424 -124.02566)
		(end 427.826424 -123.349512)
		(width 0.381)
		(layer "F.Cu")
		(net "GND")
	)
	(segment
		(start 159.918146 -304.416714)
		(end 158.813246 -304.416714)
		(width 0.381)
		(layer "F.Cu")
		(net "GND")
	)
	(segment
		(start 166.357046 -246.616728)
		(end 167.461946 -246.616728)
		(width 0.381)
		(layer "F.Cu")
		(net "GND")
	)
	(segment
		(start 464.764882 -308.666642)
		(end 463.659982 -308.666642)
		(width 0.381)
		(layer "F.Cu")
		(net "GND")
	)
	(segment
		(start 260.180582 -241.516662)
		(end 259.075682 -241.516662)
		(width 0.381)
		(layer "F.Cu")
		(net "GND")
	)
	(segment
		(start 266.619482 -294.216582)
		(end 267.724382 -294.216582)
		(width 0.381)
		(layer "F.Cu")
		(net "GND")
	)
	(segment
		(start 102.036626 -333.330804)
		(end 101.83114 -333.125318)
		(width 0.2032)
		(layer "F.Cu")
		(net "GND")
	)
	(segment
		(start 14.01826 -92.287598)
		(end 14.01826 -91.658948)
		(width 0.3556)
		(layer "F.Cu")
		(net "GND")
	)
	(segment
		(start 419.502082 -200.716642)
		(end 418.397182 -200.716642)
		(width 0.381)
		(layer "F.Cu")
		(net "GND")
	)
	(segment
		(start 271.168114 -295.06672)
		(end 270.063214 -295.06672)
		(width 0.381)
		(layer "F.Cu")
		(net "GND")
	)
	(segment
		(start 375.55678 -229.808786)
		(end 375.557034 -229.808532)
		(width 0.2032)
		(layer "F.Cu")
		(net "GND")
	)
	(segment
		(start 452.016114 -231.316784)
		(end 450.911214 -231.316784)
		(width 0.381)
		(layer "F.Cu")
		(net "GND")
	)
	(segment
		(start 199.527414 -316.316614)
		(end 200.632314 -316.316614)
		(width 0.381)
		(layer "F.Cu")
		(net "GND")
	)
	(segment
		(start 129.966466 -235.506006)
		(end 129.966212 -235.505752)
		(width 0.2032)
		(layer "F.Cu")
		(net "GND")
	)
	(segment
		(start 130.906012 -240.388902)
		(end 130.906012 -239.853216)
		(width 0.2032)
		(layer "F.Cu")
		(net "GND")
	)
	(segment
		(start 117.859048 -280.242264)
		(end 117.859048 -280.778204)
		(width 0.254)
		(layer "F.Cu")
		(net "GND")
	)
	(segment
		(start 38.315646 -238.966756)
		(end 37.210746 -238.966756)
		(width 0.381)
		(layer "F.Cu")
		(net "GND")
	)
	(segment
		(start 97.543112 -226.553268)
		(end 97.543112 -226.017582)
		(width 0.254)
		(layer "F.Cu")
		(net "GND")
	)
	(segment
		(start 122.019822 -115.178586)
		(end 122.019822 -116.042948)
		(width 0.3556)
		(layer "F.Cu")
		(net "GND")
	)
	(segment
		(start 207.071214 -310.366664)
		(end 208.176114 -310.366664)
		(width 0.381)
		(layer "F.Cu")
		(net "GND")
	)
	(segment
		(start 452.016114 -300.166786)
		(end 450.911214 -300.166786)
		(width 0.381)
		(layer "F.Cu")
		(net "GND")
	)
	(segment
		(start 266.619482 -316.316614)
		(end 267.724382 -316.316614)
		(width 0.381)
		(layer "F.Cu")
		(net "GND")
	)
	(segment
		(start 173.900846 -281.466798)
		(end 175.005746 -281.466798)
		(width 0.381)
		(layer "F.Cu")
		(net "GND")
	)
	(segment
		(start 29.666946 -212.616796)
		(end 30.771846 -212.616796)
		(width 0.381)
		(layer "F.Cu")
		(net "GND")
	)
	(segment
		(start 16.789146 -258.516628)
		(end 15.684246 -258.516628)
		(width 0.381)
		(layer "F.Cu")
		(net "GND")
	)
	(segment
		(start 166.357046 -197.316598)
		(end 165.252146 -197.316598)
		(width 0.381)
		(layer "F.Cu")
		(net "GND")
	)
	(segment
		(start 371.907562 -279.428194)
		(end 371.907562 -279.964134)
		(width 0.254)
		(layer "F.Cu")
		(net "GND")
	)
	(segment
		(start 128.666494 -289.195002)
		(end 128.666494 -289.807142)
		(width 0.2032)
		(layer "F.Cu")
		(net "GND")
	)
	(segment
		(start 343.133934 -217.600276)
		(end 343.133934 -217.064336)
		(width 0.2032)
		(layer "F.Cu")
		(net "GND")
	)
	(segment
		(start 334.05064 -54.558946)
		(end 334.864456 -54.089046)
		(width 0.2032)
		(layer "F.Cu")
		(net "GND")
	)
	(segment
		(start 435.823614 -197.316598)
		(end 436.928514 -197.316598)
		(width 0.381)
		(layer "F.Cu")
		(net "GND")
	)
	(segment
		(start 194.35953 -350.510348)
		(end 195.20408 -350.510348)
		(width 0.3556)
		(layer "F.Cu")
		(net "GND")
	)
	(segment
		(start 457.221082 -230.466646)
		(end 456.116182 -230.466646)
		(width 0.381)
		(layer "F.Cu")
		(net "GND")
	)
	(segment
		(start 356.291134 -214.344758)
		(end 356.291134 -213.732618)
		(width 0.254)
		(layer "F.Cu")
		(net "GND")
	)
	(segment
		(start 57.503314 -275.516594)
		(end 58.608214 -275.516594)
		(width 0.381)
		(layer "F.Cu")
		(net "GND")
	)
	(segment
		(start 125.737112 -216.78646)
		(end 125.737112 -216.250774)
		(width 0.254)
		(layer "F.Cu")
		(net "GND")
	)
	(segment
		(start 123.967494 -279.428194)
		(end 123.967494 -279.964134)
		(width 0.2032)
		(layer "F.Cu")
		(net "GND")
	)
	(segment
		(start 289.67811 -95.760794)
		(end 289.67811 -96.416368)
		(width 0.3556)
		(layer "F.Cu")
		(net "GND")
	)
	(segment
		(start 170.457114 -278.916638)
		(end 169.352214 -278.916638)
		(width 0.381)
		(layer "F.Cu")
		(net "GND")
	)
	(segment
		(start 340.78418 -216.78646)
		(end 340.78418 -216.250774)
		(width 0.254)
		(layer "F.Cu")
		(net "GND")
	)
	(segment
		(start 94.723966 -231.436164)
		(end 94.723966 -230.900478)
		(width 0.2032)
		(layer "F.Cu")
		(net "GND")
	)
	(segment
		(start 92.954094 -265.313922)
		(end 92.954348 -265.314176)
		(width 0.2032)
		(layer "F.Cu")
		(net "GND")
	)
	(segment
		(start 103.291894 -282.683966)
		(end 103.291894 -283.219906)
		(width 0.2032)
		(layer "F.Cu")
		(net "GND")
	)
	(segment
		(start 277.607014 -206.666592)
		(end 278.711914 -206.666592)
		(width 0.381)
		(layer "F.Cu")
		(net "GND")
	)
	(segment
		(start 272.687796 -131.586732)
		(end 270.843248 -131.586732)
		(width 0.3556)
		(layer "F.Cu")
		(net "GND")
	)
	(segment
		(start 416.484562 -164.879528)
		(end 416.055302 -165.308788)
		(width 0.2032)
		(layer "F.Cu")
		(net "GND")
	)
	(segment
		(start 349.242634 -246.086376)
		(end 349.242634 -245.55069)
		(width 0.2032)
		(layer "F.Cu")
		(net "GND")
	)
	(segment
		(start 97.073466 -250.155964)
		(end 97.073466 -249.620024)
		(width 0.2032)
		(layer "F.Cu")
		(net "GND")
	)
	(segment
		(start 97.653094 -282.683966)
		(end 97.653094 -283.219906)
		(width 0.2032)
		(layer "F.Cu")
		(net "GND")
	)
	(segment
		(start 372.377716 -259.081016)
		(end 372.377716 -259.093462)
		(width 0.2032)
		(layer "F.Cu")
		(net "GND")
	)
	(segment
		(start 329.89647 -57.605168)
		(end 330.492354 -57.2643)
		(width 0.2032)
		(layer "F.Cu")
		(net "GND")
	)
	(segment
		(start 20.889214 -244.066568)
		(end 19.784314 -244.066568)
		(width 0.381)
		(layer "F.Cu")
		(net "GND")
	)
	(segment
		(start 22.123146 -199.01662)
		(end 23.228046 -199.01662)
		(width 0.381)
		(layer "F.Cu")
		(net "GND")
	)
	(segment
		(start 441.028582 -235.566712)
		(end 442.133482 -235.566712)
		(width 0.381)
		(layer "F.Cu")
		(net "GND")
	)
	(segment
		(start 256.080514 -250.016772)
		(end 257.185414 -250.016772)
		(width 0.381)
		(layer "F.Cu")
		(net "GND")
	)
	(segment
		(start 419.502082 -258.516628)
		(end 418.397182 -258.516628)
		(width 0.381)
		(layer "F.Cu")
		(net "GND")
	)
	(segment
		(start 99.532948 -271.289526)
		(end 99.532948 -271.825212)
		(width 0.2032)
		(layer "F.Cu")
		(net "GND")
	)
	(segment
		(start 256.080514 -248.31675)
		(end 257.185414 -248.31675)
		(width 0.381)
		(layer "F.Cu")
		(net "GND")
	)
	(segment
		(start 19.784314 -226.216718)
		(end 20.889214 -226.216718)
		(width 0.381)
		(layer "F.Cu")
		(net "GND")
	)
	(segment
		(start 196.532246 -317.166752)
		(end 195.427346 -317.166752)
		(width 0.381)
		(layer "F.Cu")
		(net "GND")
	)
	(segment
		(start 263.624314 -304.416714)
		(end 264.729214 -304.416714)
		(width 0.381)
		(layer "F.Cu")
		(net "GND")
	)
	(segment
		(start 342.664034 -241.202972)
		(end 342.664034 -240.667286)
		(width 0.2032)
		(layer "F.Cu")
		(net "GND")
	)
	(segment
		(start 173.355762 -118.575328)
		(end 172.955712 -118.975378)
		(width 0.3556)
		(layer "F.Cu")
		(net "GND")
	)
	(segment
		(start 277.607014 -248.31675)
		(end 278.711914 -248.31675)
		(width 0.381)
		(layer "F.Cu")
		(net "GND")
	)
	(segment
		(start 372.377716 -270.475456)
		(end 372.377462 -271.011396)
		(width 0.2032)
		(layer "F.Cu")
		(net "GND")
	)
	(segment
		(start 355.461316 -286.7533)
		(end 355.461316 -287.288986)
		(width 0.254)
		(layer "F.Cu")
		(net "GND")
	)
	(segment
		(start 215.719914 -312.91657)
		(end 216.824814 -312.91657)
		(width 0.381)
		(layer "F.Cu")
		(net "GND")
	)
	(segment
		(start 138.534648 -254.197612)
		(end 139.477496 -254.197612)
		(width 0.2032)
		(layer "F.Cu")
		(net "GND")
	)
	(segment
		(start 344.54338 -247.714262)
		(end 344.54338 -247.178322)
		(width 0.2032)
		(layer "F.Cu")
		(net "GND")
	)
	(segment
		(start 52.298346 -304.416714)
		(end 53.403246 -304.416714)
		(width 0.381)
		(layer "F.Cu")
		(net "GND")
	)
	(segment
		(start 135.605266 -248.528078)
		(end 135.605266 -247.992138)
		(width 0.254)
		(layer "F.Cu")
		(net "GND")
	)
	(segment
		(start 102.036626 -333.763112)
		(end 102.036626 -333.330804)
		(width 0.2032)
		(layer "F.Cu")
		(net "GND")
	)
	(segment
		(start 436.928514 -231.316784)
		(end 438.033414 -231.316784)
		(width 0.381)
		(layer "F.Cu")
		(net "GND")
	)
	(segment
		(start 353.111562 -281.05608)
		(end 353.111816 -281.59202)
		(width 0.2032)
		(layer "F.Cu")
		(net "GND")
	)
	(segment
		(start 453.121014 -199.01662)
		(end 452.016114 -199.01662)
		(width 0.381)
		(layer "F.Cu")
		(net "GND")
	)
	(segment
		(start 365.689134 -223.575626)
		(end 365.689134 -224.111566)
		(width 0.2032)
		(layer "F.Cu")
		(net "GND")
	)
	(segment
		(start 375.197116 -286.7533)
		(end 375.197116 -287.288986)
		(width 0.254)
		(layer "F.Cu")
		(net "GND")
	)
	(segment
		(start 174.80788 -97.934018)
		(end 174.82566 -97.916238)
		(width 0.3556)
		(layer "F.Cu")
		(net "GND")
	)
	(segment
		(start 44.754546 -199.01662)
		(end 45.859446 -199.01662)
		(width 0.381)
		(layer "F.Cu")
		(net "GND")
	)
	(segment
		(start 349.822516 -275.894546)
		(end 349.822262 -275.8948)
		(width 0.254)
		(layer "F.Cu")
		(net "GND")
	)
	(segment
		(start 275.373084 -17.678908)
		(end 275.373084 -17.043908)
		(width 0.3556)
		(layer "F.Cu")
		(net "GND")
	)
	(segment
		(start 208.176114 -299.316648)
		(end 209.281014 -299.316648)
		(width 0.381)
		(layer "F.Cu")
		(net "GND")
	)
	(segment
		(start 129.606294 -262.058404)
		(end 129.606548 -262.058658)
		(width 0.254)
		(layer "F.Cu")
		(net "GND")
	)
	(segment
		(start 87.205312 -233.064304)
		(end 87.205312 -232.528618)
		(width 0.254)
		(layer "F.Cu")
		(net "GND")
	)
	(segment
		(start 71.05396 -52.728876)
		(end 71.33717 -53.012086)
		(width 0.3556)
		(layer "F.Cu")
		(net "GND")
	)
	(segment
		(start 459.559914 -208.366614)
		(end 458.455014 -208.366614)
		(width 0.381)
		(layer "F.Cu")
		(net "GND")
	)
	(segment
		(start 328.895964 -37.357558)
		(end 328.834496 -37.209222)
		(width 0.2032)
		(layer "F.Cu")
		(net "GND")
	)
	(segment
		(start 14.579346 -260.21665)
		(end 15.684246 -260.21665)
		(width 0.381)
		(layer "F.Cu")
		(net "GND")
	)
	(segment
		(start 355.82098 -222.76181)
		(end 355.821234 -222.761556)
		(width 0.254)
		(layer "F.Cu")
		(net "GND")
	)
	(segment
		(start 418.397182 -245.76659)
		(end 417.292282 -245.76659)
		(width 0.381)
		(layer "F.Cu")
		(net "GND")
	)
	(segment
		(start 14.579346 -244.916706)
		(end 15.684246 -244.916706)
		(width 0.381)
		(layer "F.Cu")
		(net "GND")
	)
	(segment
		(start 421.840914 -248.31675)
		(end 422.945814 -248.31675)
		(width 0.381)
		(layer "F.Cu")
		(net "GND")
	)
	(segment
		(start 374.14708 -232.250234)
		(end 374.14708 -231.714548)
		(width 0.2032)
		(layer "F.Cu")
		(net "GND")
	)
	(segment
		(start 45.859446 -221.96679)
		(end 46.964346 -221.96679)
		(width 0.381)
		(layer "F.Cu")
		(net "GND")
	)
	(segment
		(start 463.659982 -258.516628)
		(end 464.764882 -258.516628)
		(width 0.381)
		(layer "F.Cu")
		(net "GND")
	)
	(segment
		(start 135.245094 -282.683966)
		(end 135.245094 -283.219906)
		(width 0.254)
		(layer "F.Cu")
		(net "GND")
	)
	(segment
		(start 43.520614 -226.216718)
		(end 42.415714 -226.216718)
		(width 0.381)
		(layer "F.Cu")
		(net "GND")
	)
	(segment
		(start 18.54708 -10.16508)
		(end 18.54708 -11.26998)
		(width 0.3556)
		(layer "F.Cu")
		(net "GND")
	)
	(segment
		(start 122.087894 -282.683966)
		(end 122.087894 -283.219906)
		(width 0.254)
		(layer "F.Cu")
		(net "GND")
	)
	(segment
		(start 439.923682 -198.166736)
		(end 441.028582 -198.166736)
		(width 0.381)
		(layer "F.Cu")
		(net "GND")
	)
	(segment
		(start 425.940982 -277.216616)
		(end 424.836082 -277.216616)
		(width 0.381)
		(layer "F.Cu")
		(net "GND")
	)
	(segment
		(start 301.343314 -290.816792)
		(end 302.448214 -290.816792)
		(width 0.381)
		(layer "F.Cu")
		(net "GND")
	)
	(segment
		(start 30.771846 -273.816572)
		(end 31.876746 -273.816572)
		(width 0.381)
		(layer "F.Cu")
		(net "GND")
	)
	(segment
		(start 185.544714 -221.116652)
		(end 186.649614 -221.116652)
		(width 0.381)
		(layer "F.Cu")
		(net "GND")
	)
	(segment
		(start 89.664794 -278.614378)
		(end 89.66454 -279.14981)
		(width 0.2032)
		(layer "F.Cu")
		(net "GND")
	)
	(segment
		(start 39.263574 -386.940806)
		(end 39.263574 -386.329174)
		(width 0.4572)
		(layer "F.Cu")
		(net "GND")
	)
	(segment
		(start 418.397182 -228.766624)
		(end 417.292282 -228.766624)
		(width 0.381)
		(layer "F.Cu")
		(net "GND")
	)
	(segment
		(start 101.882448 -272.639028)
		(end 101.882194 -272.639282)
		(width 0.2032)
		(layer "F.Cu")
		(net "GND")
	)
	(segment
		(start 394.899896 -53.824886)
		(end 394.899896 -50.895504)
		(width 0.3556)
		(layer "F.Cu")
		(net "GND")
	)
	(segment
		(start 277.607014 -240.666778)
		(end 278.711914 -240.666778)
		(width 0.381)
		(layer "F.Cu")
		(net "GND")
	)
	(segment
		(start 29.666946 -298.466764)
		(end 30.771846 -298.466764)
		(width 0.381)
		(layer "F.Cu")
		(net "GND")
	)
	(segment
		(start 132.315966 -249.341894)
		(end 132.315966 -248.806208)
		(width 0.2032)
		(layer "F.Cu")
		(net "GND")
	)
	(segment
		(start 71.79056 -55.270908)
		(end 71.79056 -54.381908)
		(width 0.3556)
		(layer "F.Cu")
		(net "GND")
	)
	(segment
		(start 99.422966 -229.808532)
		(end 99.422966 -229.272846)
		(width 0.2032)
		(layer "F.Cu")
		(net "GND")
	)
	(segment
		(start 29.666946 -206.666592)
		(end 30.771846 -206.666592)
		(width 0.381)
		(layer "F.Cu")
		(net "GND")
	)
	(segment
		(start 207.071214 -306.96662)
		(end 208.176114 -306.96662)
		(width 0.381)
		(layer "F.Cu")
		(net "GND")
	)
	(segment
		(start 125.737112 -222.76181)
		(end 125.737366 -222.761556)
		(width 0.254)
		(layer "F.Cu")
		(net "GND")
	)
	(segment
		(start 173.900846 -272.116804)
		(end 172.795946 -272.116804)
		(width 0.381)
		(layer "F.Cu")
		(net "GND")
	)
	(segment
		(start 130.436112 -226.017582)
		(end 130.436366 -226.017328)
		(width 0.254)
		(layer "F.Cu")
		(net "GND")
	)
	(segment
		(start 57.503314 -247.466612)
		(end 58.608214 -247.466612)
		(width 0.381)
		(layer "F.Cu")
		(net "GND")
	)
	(segment
		(start 30.771846 -267.016738)
		(end 31.876746 -267.016738)
		(width 0.381)
		(layer "F.Cu")
		(net "GND")
	)
	(segment
		(start 124.327666 -233.87812)
		(end 124.327412 -233.877866)
		(width 0.254)
		(layer "F.Cu")
		(net "GND")
	)
	(segment
		(start 204.076046 -244.916706)
		(end 205.180946 -244.916706)
		(width 0.381)
		(layer "F.Cu")
		(net "GND")
	)
	(segment
		(start 445.577214 -268.71676)
		(end 444.472314 -268.71676)
		(width 0.381)
		(layer "F.Cu")
		(net "GND")
	)
	(segment
		(start 449.677282 -282.316682)
		(end 448.572382 -282.316682)
		(width 0.381)
		(layer "F.Cu")
		(net "GND")
	)
	(segment
		(start 418.397182 -280.61666)
		(end 417.292282 -280.61666)
		(width 0.381)
		(layer "F.Cu")
		(net "GND")
	)
	(segment
		(start 347.472762 -261.522718)
		(end 347.472762 -262.058404)
		(width 0.254)
		(layer "F.Cu")
		(net "GND")
	)
	(segment
		(start 303.58715 -24.7396)
		(end 302.8442 -24.7396)
		(width 0.3556)
		(layer "F.Cu")
		(net "GND")
	)
	(segment
		(start 23.669752 -412.450534)
		(end 23.060152 -412.450534)
		(width 0.381)
		(layer "F.Cu")
		(net "GND")
	)
	(segment
		(start 125.377448 -272.103342)
		(end 125.377448 -272.639282)
		(width 0.2032)
		(layer "F.Cu")
		(net "GND")
	)
	(segment
		(start 122.917966 -231.436164)
		(end 122.917966 -230.900478)
		(width 0.254)
		(layer "F.Cu")
		(net "GND")
	)
	(segment
		(start 300.238414 -315.46673)
		(end 301.343314 -315.46673)
		(width 0.381)
		(layer "F.Cu")
		(net "GND")
	)
	(segment
		(start 420.736014 -315.46673)
		(end 421.840914 -315.46673)
		(width 0.381)
		(layer "F.Cu")
		(net "GND")
	)
	(segment
		(start 363.684566 -358.74198)
		(end 363.492796 -358.93375)
		(width 0.3556)
		(layer "F.Cu")
		(net "GND")
	)
	(segment
		(start 113.629694 -263.150604)
		(end 113.629694 -263.686036)
		(width 0.254)
		(layer "F.Cu")
		(net "GND")
	)
	(segment
		(start 230.984298 -51.565048)
		(end 232.000044 -51.565048)
		(width 0.381)
		(layer "F.Cu")
		(net "GND")
	)
	(segment
		(start 293.799514 -220.266768)
		(end 292.694614 -220.266768)
		(width 0.381)
		(layer "F.Cu")
		(net "GND")
	)
	(segment
		(start 280.810462 -90.54465)
		(end 281.794966 -91.529154)
		(width 0.3556)
		(layer "F.Cu")
		(net "GND")
	)
	(segment
		(start 90.024712 -220.041978)
		(end 90.024966 -220.041724)
		(width 0.254)
		(layer "F.Cu")
		(net "GND")
	)
	(segment
		(start 100.832666 -248.528078)
		(end 100.832412 -248.527824)
		(width 0.2032)
		(layer "F.Cu")
		(net "GND")
	)
	(segment
		(start 193.088514 -291.666676)
		(end 194.193414 -291.666676)
		(width 0.381)
		(layer "F.Cu")
		(net "GND")
	)
	(segment
		(start 443.367414 -246.616728)
		(end 444.472314 -246.616728)
		(width 0.381)
		(layer "F.Cu")
		(net "GND")
	)
	(segment
		(start 109.980984 -395.17574)
		(end 109.980984 -395.813788)
		(width 0.3556)
		(layer "F.Cu")
		(net "GND")
	)
	(segment
		(start 93.830902 -336.27314)
		(end 93.511624 -336.592418)
		(width 0.254)
		(layer "F.Cu")
		(net "GND")
	)
	(segment
		(start 126.676912 -242.830858)
		(end 126.676912 -242.295172)
		(width 0.2032)
		(layer "F.Cu")
		(net "GND")
	)
	(segment
		(start 444.472314 -315.46673)
		(end 445.577214 -315.46673)
		(width 0.381)
		(layer "F.Cu")
		(net "GND")
	)
	(segment
		(start 89.084912 -224.925382)
		(end 89.084912 -224.389696)
		(width 0.254)
		(layer "F.Cu")
		(net "GND")
	)
	(segment
		(start 370.85778 -223.297496)
		(end 370.85778 -222.76181)
		(width 0.254)
		(layer "F.Cu")
		(net "GND")
	)
	(segment
		(start 382.715516 -281.869896)
		(end 382.715516 -282.405836)
		(width 0.254)
		(layer "F.Cu")
		(net "GND")
	)
	(segment
		(start 405.648414 -267.016738)
		(end 406.753314 -267.016738)
		(width 0.381)
		(layer "F.Cu")
		(net "GND")
	)
	(segment
		(start 380.365762 -271.289272)
		(end 380.365762 -271.825212)
		(width 0.2032)
		(layer "F.Cu")
		(net "GND")
	)
	(segment
		(start 378.956316 -266.127992)
		(end 378.956062 -266.128246)
		(width 0.254)
		(layer "F.Cu")
		(net "GND")
	)
	(segment
		(start 424.836082 -249.166634)
		(end 425.940982 -249.166634)
		(width 0.381)
		(layer "F.Cu")
		(net "GND")
	)
	(segment
		(start 34.871914 -224.516696)
		(end 35.976814 -224.516696)
		(width 0.381)
		(layer "F.Cu")
		(net "GND")
	)
	(segment
		(start 266.619482 -211.766658)
		(end 267.724382 -211.766658)
		(width 0.381)
		(layer "F.Cu")
		(net "GND")
	)
	(segment
		(start 354.411534 -217.600276)
		(end 354.411534 -217.064336)
		(width 0.2032)
		(layer "F.Cu")
		(net "GND")
	)
	(segment
		(start 355.461316 -288.381186)
		(end 355.461316 -288.917126)
		(width 0.254)
		(layer "F.Cu")
		(net "GND")
	)
	(segment
		(start 134.305294 -264.778236)
		(end 134.305548 -265.314176)
		(width 0.2032)
		(layer "F.Cu")
		(net "GND")
	)
	(segment
		(start 358.640634 -223.297496)
		(end 358.640634 -222.761556)
		(width 0.254)
		(layer "F.Cu")
		(net "GND")
	)
	(segment
		(start 136.946894 -17.655032)
		(end 136.946894 -16.550132)
		(width 0.3556)
		(layer "F.Cu")
		(net "GND")
	)
	(segment
		(start 457.7461 -380.84887)
		(end 457.730098 -380.864872)
		(width 0.381)
		(layer "F.Cu")
		(net "GND")
	)
	(segment
		(start 94.364048 -280.242264)
		(end 94.364048 -280.778204)
		(width 0.254)
		(layer "F.Cu")
		(net "GND")
	)
	(segment
		(start 212.724746 -300.166786)
		(end 211.619846 -300.166786)
		(width 0.381)
		(layer "F.Cu")
		(net "GND")
	)
	(segment
		(start 428.279814 -240.666778)
		(end 429.384714 -240.666778)
		(width 0.381)
		(layer "F.Cu")
		(net "GND")
	)
	(segment
		(start 216.788238 -23.017988)
		(end 216.943178 -23.172928)
		(width 0.3556)
		(layer "F.Cu")
		(net "GND")
	)
	(segment
		(start 131.016248 -256.361184)
		(end 131.015994 -256.361438)
		(width 0.254)
		(layer "F.Cu")
		(net "GND")
	)
	(segment
		(start 453.121014 -208.366614)
		(end 452.016114 -208.366614)
		(width 0.381)
		(layer "F.Cu")
		(net "GND")
	)
	(segment
		(start 409.748482 -306.96662)
		(end 410.853382 -306.96662)
		(width 0.381)
		(layer "F.Cu")
		(net "GND")
	)
	(segment
		(start 138.894312 -231.436418)
		(end 139.364466 -231.714548)
		(width 0.254)
		(layer "F.Cu")
		(net "GND")
	)
	(segment
		(start 96.133412 -245.272306)
		(end 96.133412 -244.73662)
		(width 0.2032)
		(layer "F.Cu")
		(net "GND")
	)
	(segment
		(start 81.48955 -41.036748)
		(end 81.48955 -40.401748)
		(width 0.3556)
		(layer "F.Cu")
		(net "GND")
	)
	(segment
		(start 406.753314 -317.166752)
		(end 405.648414 -317.166752)
		(width 0.381)
		(layer "F.Cu")
		(net "GND")
	)
	(segment
		(start 104.121966 -231.436164)
		(end 104.121966 -230.900478)
		(width 0.2032)
		(layer "F.Cu")
		(net "GND")
	)
	(segment
		(start 117.388894 -271.289272)
		(end 117.389148 -271.825212)
		(width 0.2032)
		(layer "F.Cu")
		(net "GND")
	)
	(segment
		(start 445.577214 -263.616694)
		(end 444.472314 -263.616694)
		(width 0.381)
		(layer "F.Cu")
		(net "GND")
	)
	(segment
		(start 341.105744 -40.462454)
		(end 341.37727 -40.931846)
		(width 0.254)
		(layer "F.Cu")
		(net "GND")
	)
	(segment
		(start 123.027694 -281.05608)
		(end 123.027694 -281.591512)
		(width 0.254)
		(layer "F.Cu")
		(net "GND")
	)
	(segment
		(start 21.348192 -399.932144)
		(end 22.364192 -399.932144)
		(width 0.4572)
		(layer "F.Cu")
		(net "GND")
	)
	(segment
		(start 9.245346 -272.116804)
		(end 8.140446 -272.116804)
		(width 0.381)
		(layer "F.Cu")
		(net "GND")
	)
	(segment
		(start 271.168114 -208.366614)
		(end 270.063214 -208.366614)
		(width 0.381)
		(layer "F.Cu")
		(net "GND")
	)
	(segment
		(start 256.080514 -263.616694)
		(end 257.185414 -263.616694)
		(width 0.381)
		(layer "F.Cu")
		(net "GND")
	)
	(segment
		(start 256.080514 -315.46673)
		(end 257.185414 -315.46673)
		(width 0.381)
		(layer "F.Cu")
		(net "GND")
	)
	(segment
		(start 204.076046 -214.316564)
		(end 205.180946 -214.316564)
		(width 0.381)
		(layer "F.Cu")
		(net "GND")
	)
	(segment
		(start 59.842146 -281.466798)
		(end 60.947046 -281.466798)
		(width 0.381)
		(layer "F.Cu")
		(net "GND")
	)
	(segment
		(start 261.285482 -219.41663)
		(end 260.180582 -219.41663)
		(width 0.381)
		(layer "F.Cu")
		(net "GND")
	)
	(segment
		(start 336.665316 -286.7533)
		(end 336.665316 -287.288986)
		(width 0.254)
		(layer "F.Cu")
		(net "GND")
	)
	(segment
		(start 123.027694 -281.591512)
		(end 123.027948 -281.591766)
		(width 0.254)
		(layer "F.Cu")
		(net "GND")
	)
	(segment
		(start 132.750814 -113.741708)
		(end 133.843014 -113.741708)
		(width 0.3556)
		(layer "F.Cu")
		(net "GND")
	)
	(segment
		(start 374.481852 -339.52561)
		(end 374.481852 -339.296756)
		(width 0.2032)
		(layer "F.Cu")
		(net "GND")
	)
	(segment
		(start 290.355782 -289.966654)
		(end 291.460682 -289.966654)
		(width 0.381)
		(layer "F.Cu")
		(net "GND")
	)
	(segment
		(start 214.615014 -198.166736)
		(end 215.719914 -198.166736)
		(width 0.381)
		(layer "F.Cu")
		(net "GND")
	)
	(segment
		(start 137.153396 -263.709404)
		(end 137.130536 -263.686544)
		(width 0.254)
		(layer "F.Cu")
		(net "GND")
	)
	(segment
		(start 215.719914 -244.066568)
		(end 216.824814 -244.066568)
		(width 0.381)
		(layer "F.Cu")
		(net "GND")
	)
	(segment
		(start 91.074494 -276.172676)
		(end 91.074494 -276.708616)
		(width 0.2032)
		(layer "F.Cu")
		(net "GND")
	)
	(segment
		(start 208.176114 -308.666642)
		(end 209.281014 -308.666642)
		(width 0.381)
		(layer "F.Cu")
		(net "GND")
	)
	(segment
		(start 432.379882 -261.066788)
		(end 433.484782 -261.066788)
		(width 0.381)
		(layer "F.Cu")
		(net "GND")
	)
	(segment
		(start 96.133412 -228.994716)
		(end 96.133412 -228.45903)
		(width 0.2032)
		(layer "F.Cu")
		(net "GND")
	)
	(segment
		(start 351.701862 -267.220192)
		(end 351.701862 -267.755878)
		(width 0.254)
		(layer "F.Cu")
		(net "GND")
	)
	(segment
		(start 54.724046 -236.416596)
		(end 53.403246 -236.416596)
		(width 0.381)
		(layer "F.Cu")
		(net "GND")
	)
	(segment
		(start 337.142328 -21.29282)
		(end 337.142328 -20.434554)
		(width 0.3556)
		(layer "F.Cu")
		(net "GND")
	)
	(segment
		(start 425.940982 -210.066636)
		(end 427.045882 -210.066636)
		(width 0.381)
		(layer "F.Cu")
		(net "GND")
	)
	(segment
		(start 120.098312 -220.041978)
		(end 120.098566 -220.041724)
		(width 0.254)
		(layer "F.Cu")
		(net "GND")
	)
	(segment
		(start 84.966048 -259.081016)
		(end 84.495894 -258.80314)
		(width 0.254)
		(layer "F.Cu")
		(net "GND")
	)
	(segment
		(start 290.355782 -271.266666)
		(end 291.460682 -271.266666)
		(width 0.381)
		(layer "F.Cu")
		(net "GND")
	)
	(segment
		(start 185.544714 -238.116618)
		(end 186.649614 -238.116618)
		(width 0.381)
		(layer "F.Cu")
		(net "GND")
	)
	(segment
		(start 134.775448 -286.7533)
		(end 134.775448 -287.28924)
		(width 0.254)
		(layer "F.Cu")
		(net "GND")
	)
	(segment
		(start 166.357046 -238.966756)
		(end 167.461946 -238.966756)
		(width 0.381)
		(layer "F.Cu")
		(net "GND")
	)
	(segment
		(start 166.357046 -276.366732)
		(end 167.665146 -276.366732)
		(width 0.381)
		(layer "F.Cu")
		(net "GND")
	)
	(segment
		(start 293.799514 -285.716726)
		(end 292.694614 -285.716726)
		(width 0.381)
		(layer "F.Cu")
		(net "GND")
	)
	(segment
		(start 164.018214 -245.76659)
		(end 162.913314 -245.76659)
		(width 0.381)
		(layer "F.Cu")
		(net "GND")
	)
	(segment
		(start 304.338482 -306.96662)
		(end 305.443382 -306.96662)
		(width 0.381)
		(layer "F.Cu")
		(net "GND")
	)
	(segment
		(start 285.150814 -272.116804)
		(end 286.255714 -272.116804)
		(width 0.381)
		(layer "F.Cu")
		(net "GND")
	)
	(segment
		(start 293.497 -343.760044)
		(end 293.497 -344.700352)
		(width 0.508)
		(layer "F.Cu")
		(net "GND")
	)
	(segment
		(start 131.3815 -42.784522)
		(end 130.7719 -42.784522)
		(width 0.3556)
		(layer "F.Cu")
		(net "GND")
	)
	(segment
		(start 23.228046 -317.166752)
		(end 24.332946 -317.166752)
		(width 0.381)
		(layer "F.Cu")
		(net "GND")
	)
	(segment
		(start 335.725262 -264.50036)
		(end 335.725262 -263.96442)
		(width 0.254)
		(layer "F.Cu")
		(net "GND")
	)
	(segment
		(start 214.615014 -219.41663)
		(end 215.719914 -219.41663)
		(width 0.381)
		(layer "F.Cu")
		(net "GND")
	)
	(segment
		(start 118.328694 -268.033754)
		(end 118.328948 -268.569694)
		(width 0.254)
		(layer "F.Cu")
		(net "GND")
	)
	(segment
		(start 459.559914 -317.166752)
		(end 460.664814 -317.166752)
		(width 0.381)
		(layer "F.Cu")
		(net "GND")
	)
	(segment
		(start 449.677282 -232.166668)
		(end 448.572382 -232.166668)
		(width 0.381)
		(layer "F.Cu")
		(net "GND")
	)
	(segment
		(start 267.724382 -200.716642)
		(end 268.829282 -200.716642)
		(width 0.381)
		(layer "F.Cu")
		(net "GND")
	)
	(segment
		(start 45.859446 -313.766708)
		(end 46.964346 -313.766708)
		(width 0.381)
		(layer "F.Cu")
		(net "GND")
	)
	(segment
		(start 293.799514 -315.46673)
		(end 294.904414 -315.46673)
		(width 0.381)
		(layer "F.Cu")
		(net "GND")
	)
	(segment
		(start 279.816814 -197.316598)
		(end 278.711914 -197.316598)
		(width 0.381)
		(layer "F.Cu")
		(net "GND")
	)
	(segment
		(start 181.444646 -204.96657)
		(end 182.549546 -204.96657)
		(width 0.381)
		(layer "F.Cu")
		(net "GND")
	)
	(segment
		(start 87.785194 -265.592306)
		(end 87.785194 -266.128246)
		(width 0.254)
		(layer "F.Cu")
		(net "GND")
	)
	(segment
		(start 433.484782 -291.666676)
		(end 434.589682 -291.666676)
		(width 0.381)
		(layer "F.Cu")
		(net "GND")
	)
	(segment
		(start 459.559914 -311.216802)
		(end 460.664814 -311.216802)
		(width 0.381)
		(layer "F.Cu")
		(net "GND")
	)
	(segment
		(start 202.971146 -225.36658)
		(end 204.076046 -225.36658)
		(width 0.381)
		(layer "F.Cu")
		(net "GND")
	)
	(segment
		(start 129.966212 -230.622348)
		(end 129.966212 -230.086662)
		(width 0.2032)
		(layer "F.Cu")
		(net "GND")
	)
	(segment
		(start 413.192214 -208.366614)
		(end 414.297114 -208.366614)
		(width 0.381)
		(layer "F.Cu")
		(net "GND")
	)
	(segment
		(start 98.013266 -248.528078)
		(end 98.013266 -247.992138)
		(width 0.2032)
		(layer "F.Cu")
		(net "GND")
	)
	(segment
		(start 260.180582 -215.166702)
		(end 259.075682 -215.166702)
		(width 0.381)
		(layer "F.Cu")
		(net "GND")
	)
	(segment
		(start 463.659982 -297.616626)
		(end 462.555082 -297.616626)
		(width 0.381)
		(layer "F.Cu")
		(net "GND")
	)
	(segment
		(start 266.619482 -308.666642)
		(end 267.724382 -308.666642)
		(width 0.381)
		(layer "F.Cu")
		(net "GND")
	)
	(segment
		(start 124.327412 -245.272306)
		(end 124.327412 -244.73662)
		(width 0.2032)
		(layer "F.Cu")
		(net "GND")
	)
	(segment
		(start 99.92741 -53.327046)
		(end 98.79711 -53.327046)
		(width 0.3556)
		(layer "F.Cu")
		(net "GND")
	)
	(segment
		(start 200.632314 -280.61666)
		(end 201.737214 -280.61666)
		(width 0.381)
		(layer "F.Cu")
		(net "GND")
	)
	(segment
		(start 305.443382 -222.816674)
		(end 306.548282 -222.816674)
		(width 0.381)
		(layer "F.Cu")
		(net "GND")
	)
	(segment
		(start 360.51998 -216.78646)
		(end 360.51998 -216.25052)
		(width 0.254)
		(layer "F.Cu")
		(net "GND")
	)
	(segment
		(start 204.076046 -313.766708)
		(end 205.180946 -313.766708)
		(width 0.381)
		(layer "F.Cu")
		(net "GND")
	)
	(segment
		(start 123.967748 -281.591766)
		(end 123.967748 -281.59202)
		(width 0.254)
		(layer "F.Cu")
		(net "GND")
	)
	(segment
		(start 87.675466 -222.48368)
		(end 87.675466 -221.94774)
		(width 0.254)
		(layer "F.Cu")
		(net "GND")
	)
	(segment
		(start 27.328114 -288.266632)
		(end 28.433014 -288.266632)
		(width 0.381)
		(layer "F.Cu")
		(net "GND")
	)
	(segment
		(start 374.257316 -261.244588)
		(end 374.257062 -261.244842)
		(width 0.2032)
		(layer "F.Cu")
		(net "GND")
	)
	(segment
		(start 344.903552 -58.43524)
		(end 344.903552 -57.605168)
		(width 0.2032)
		(layer "F.Cu")
		(net "GND")
	)
	(segment
		(start 411.958282 -258.516628)
		(end 410.853382 -258.516628)
		(width 0.381)
		(layer "F.Cu")
		(net "GND")
	)
	(segment
		(start 449.677282 -303.566576)
		(end 448.572382 -303.566576)
		(width 0.381)
		(layer "F.Cu")
		(net "GND")
	)
	(segment
		(start 194.193414 -207.51673)
		(end 193.088514 -207.51673)
		(width 0.381)
		(layer "F.Cu")
		(net "GND")
	)
	(segment
		(start 425.96689 -11.26998)
		(end 425.96689 -10.16508)
		(width 0.3556)
		(layer "F.Cu")
		(net "GND")
	)
	(segment
		(start 30.771846 -227.066602)
		(end 31.876746 -227.066602)
		(width 0.381)
		(layer "F.Cu")
		(net "GND")
	)
	(segment
		(start 381.19558 -242.830858)
		(end 381.19558 -242.295172)
		(width 0.2032)
		(layer "F.Cu")
		(net "GND")
	)
	(segment
		(start 135.171942 -97.25787)
		(end 135.781542 -97.25787)
		(width 0.254)
		(layer "F.Cu")
		(net "GND")
	)
	(segment
		(start 462.555082 -266.1666)
		(end 463.659982 -266.1666)
		(width 0.381)
		(layer "F.Cu")
		(net "GND")
	)
	(segment
		(start 43.520614 -249.166634)
		(end 42.415714 -249.166634)
		(width 0.381)
		(layer "F.Cu")
		(net "GND")
	)
	(segment
		(start 266.619482 -305.266598)
		(end 267.724382 -305.266598)
		(width 0.381)
		(layer "F.Cu")
		(net "GND")
	)
	(segment
		(start 136.848088 -260.38937)
		(end 136.62533 -260.307836)
		(width 0.088646)
		(layer "F.Cu")
		(net "GND")
	)
	(segment
		(start 370.498116 -273.730974)
		(end 370.497862 -274.266914)
		(width 0.2032)
		(layer "F.Cu")
		(net "GND")
	)
	(segment
		(start 128.801622 -137.114026)
		(end 129.411222 -137.114026)
		(width 0.3556)
		(layer "F.Cu")
		(net "GND")
	)
	(segment
		(start 376.49658 -220.041978)
		(end 376.496834 -220.041724)
		(width 0.254)
		(layer "F.Cu")
		(net "GND")
	)
	(segment
		(start 386.474462 -283.498036)
		(end 386.474462 -284.033722)
		(width 0.2032)
		(layer "F.Cu")
		(net "GND")
	)
	(segment
		(start 251.587 -96.092518)
		(end 251.587 -95.849948)
		(width 0.2032)
		(layer "F.Cu")
		(net "GND")
	)
	(segment
		(start 211.619846 -217.716608)
		(end 212.724746 -217.716608)
		(width 0.381)
		(layer "F.Cu")
		(net "GND")
	)
	(segment
		(start 23.228046 -212.616796)
		(end 24.332946 -212.616796)
		(width 0.381)
		(layer "F.Cu")
		(net "GND")
	)
	(segment
		(start 215.719914 -314.616592)
		(end 216.824814 -314.616592)
		(width 0.381)
		(layer "F.Cu")
		(net "GND")
	)
	(segment
		(start 166.357046 -309.51678)
		(end 167.461946 -309.51678)
		(width 0.381)
		(layer "F.Cu")
		(net "GND")
	)
	(segment
		(start 306.629054 -221.255336)
		(end 306.49037 -221.116652)
		(width 0.381)
		(layer "F.Cu")
		(net "GND")
	)
	(segment
		(start 94.723712 -231.436418)
		(end 94.723966 -231.436164)
		(width 0.2032)
		(layer "F.Cu")
		(net "GND")
	)
	(segment
		(start 349.822516 -286.7533)
		(end 349.822516 -287.288986)
		(width 0.254)
		(layer "F.Cu")
		(net "GND")
	)
	(segment
		(start 169.95648 -436.768748)
		(end 169.75328 -436.971948)
		(width 0.3556)
		(layer "F.Cu")
		(net "GND")
	)
	(segment
		(start 159.918146 -248.31675)
		(end 158.813246 -248.31675)
		(width 0.381)
		(layer "F.Cu")
		(net "GND")
	)
	(segment
		(start 418.397182 -198.166736)
		(end 417.292282 -198.166736)
		(width 0.381)
		(layer "F.Cu")
		(net "GND")
	)
	(segment
		(start 360.49458 -413.641286)
		(end 360.49458 -414.274)
		(width 0.3556)
		(layer "F.Cu")
		(net "GND")
	)
	(segment
		(start 301.343314 -287.416748)
		(end 302.448214 -287.416748)
		(width 0.381)
		(layer "F.Cu")
		(net "GND")
	)
	(segment
		(start 169.04843 -425.922948)
		(end 168.43883 -425.922948)
		(width 0.3556)
		(layer "F.Cu")
		(net "GND")
	)
	(segment
		(start 282.811982 -303.566576)
		(end 283.916882 -303.566576)
		(width 0.381)
		(layer "F.Cu")
		(net "GND")
	)
	(segment
		(start 375.55678 -249.342148)
		(end 375.557034 -249.341894)
		(width 0.2032)
		(layer "F.Cu")
		(net "GND")
	)
	(segment
		(start 362.979716 -264.499852)
		(end 362.979462 -264.500106)
		(width 0.254)
		(layer "F.Cu")
		(net "GND")
	)
	(segment
		(start 137.124694 -281.05608)
		(end 137.124694 -281.59202)
		(width 0.254)
		(layer "F.Cu")
		(net "GND")
	)
	(segment
		(start 289.250882 -210.066636)
		(end 290.355782 -210.066636)
		(width 0.381)
		(layer "F.Cu")
		(net "GND")
	)
	(segment
		(start 179.494942 -31.181548)
		(end 179.194206 -30.880812)
		(width 0.17272)
		(layer "F.Cu")
		(net "GND")
	)
	(segment
		(start 311.882282 -244.066568)
		(end 312.987182 -244.066568)
		(width 0.381)
		(layer "F.Cu")
		(net "GND")
	)
	(segment
		(start 345.013534 -230.622602)
		(end 345.013534 -230.086662)
		(width 0.2032)
		(layer "F.Cu")
		(net "GND")
	)
	(segment
		(start 456.116182 -207.51673)
		(end 455.011282 -207.51673)
		(width 0.381)
		(layer "F.Cu")
		(net "GND")
	)
	(segment
		(start 345.48318 -246.08663)
		(end 345.48318 -245.55069)
		(width 0.2032)
		(layer "F.Cu")
		(net "GND")
	)
	(segment
		(start 372.267734 -228.99497)
		(end 372.26748 -228.994716)
		(width 0.254)
		(layer "F.Cu")
		(net "GND")
	)
	(segment
		(start 396.646908 -11.26998)
		(end 396.646908 -10.16508)
		(width 0.3556)
		(layer "F.Cu")
		(net "GND")
	)
	(segment
		(start 96.243648 -275.894546)
		(end 96.243394 -275.8948)
		(width 0.2032)
		(layer "F.Cu")
		(net "GND")
	)
	(segment
		(start 42.415714 -291.666676)
		(end 41.310814 -291.666676)
		(width 0.381)
		(layer "F.Cu")
		(net "GND")
	)
	(segment
		(start 120.208294 -279.428194)
		(end 120.208294 -279.96388)
		(width 0.254)
		(layer "F.Cu")
		(net "GND")
	)
	(segment
		(start 131.846066 -230.622602)
		(end 131.846066 -230.086662)
		(width 0.2032)
		(layer "F.Cu")
		(net "GND")
	)
	(segment
		(start 344.183716 -275.894546)
		(end 344.183462 -275.8948)
		(width 0.2032)
		(layer "F.Cu")
		(net "GND")
	)
	(segment
		(start 119.268494 -286.47517)
		(end 119.268748 -286.475424)
		(width 0.254)
		(layer "F.Cu")
		(net "GND")
	)
	(segment
		(start 176.555654 -114.575336)
		(end 176.155604 -114.975386)
		(width 0.3556)
		(layer "F.Cu")
		(net "GND")
	)
	(segment
		(start 339.84438 -228.1809)
		(end 339.84438 -227.64496)
		(width 0.2032)
		(layer "F.Cu")
		(net "GND")
	)
	(segment
		(start 7.035546 -268.71676)
		(end 8.140446 -268.71676)
		(width 0.381)
		(layer "F.Cu")
		(net "GND")
	)
	(segment
		(start 275.268182 -207.51673)
		(end 274.163282 -207.51673)
		(width 0.381)
		(layer "F.Cu")
		(net "GND")
	)
	(segment
		(start 161.550604 -235.566712)
		(end 162.913314 -235.566712)
		(width 0.381)
		(layer "F.Cu")
		(net "GND")
	)
	(segment
		(start 381.775716 -257.45313)
		(end 381.775716 -257.98907)
		(width 0.2032)
		(layer "F.Cu")
		(net "GND")
	)
	(segment
		(start 18.753328 -428.44974)
		(end 18.753582 -428.449486)
		(width 0.3556)
		(layer "F.Cu")
		(net "GND")
	)
	(segment
		(start 133.835648 -282.405582)
		(end 133.835394 -282.405836)
		(width 0.254)
		(layer "F.Cu")
		(net "GND")
	)
	(segment
		(start 162.913314 -294.216582)
		(end 164.018214 -294.216582)
		(width 0.381)
		(layer "F.Cu")
		(net "GND")
	)
	(segment
		(start 96.133666 -233.87812)
		(end 96.133412 -233.877866)
		(width 0.2032)
		(layer "F.Cu")
		(net "GND")
	)
	(segment
		(start 11.135614 -221.116652)
		(end 12.240514 -221.116652)
		(width 0.381)
		(layer "F.Cu")
		(net "GND")
	)
	(segment
		(start 363.919516 -267.219938)
		(end 363.919262 -267.755878)
		(width 0.2032)
		(layer "F.Cu")
		(net "GND")
	)
	(segment
		(start 413.192214 -231.316784)
		(end 414.297114 -231.316784)
		(width 0.381)
		(layer "F.Cu")
		(net "GND")
	)
	(segment
		(start 130.436112 -226.553268)
		(end 130.436112 -226.017582)
		(width 0.254)
		(layer "F.Cu")
		(net "GND")
	)
	(segment
		(start 43.520614 -202.416664)
		(end 42.415714 -202.416664)
		(width 0.381)
		(layer "F.Cu")
		(net "GND")
	)
	(segment
		(start 346.42298 -226.553268)
		(end 346.42298 -226.017582)
		(width 0.254)
		(layer "F.Cu")
		(net "GND")
	)
	(segment
		(start 266.619482 -200.716642)
		(end 267.724382 -200.716642)
		(width 0.381)
		(layer "F.Cu")
		(net "GND")
	)
	(segment
		(start 123.027694 -271.289272)
		(end 123.027948 -271.825212)
		(width 0.2032)
		(layer "F.Cu")
		(net "GND")
	)
	(segment
		(start 95.13824 -414.48482)
		(end 95.17126 -414.4518)
		(width 0.3556)
		(layer "F.Cu")
		(net "GND")
	)
	(segment
		(start 421.840914 -268.71676)
		(end 422.945814 -268.71676)
		(width 0.381)
		(layer "F.Cu")
		(net "GND")
	)
	(segment
		(start 175.005746 -231.316784)
		(end 173.900846 -231.316784)
		(width 0.381)
		(layer "F.Cu")
		(net "GND")
	)
	(segment
		(start 348.882716 -270.475456)
		(end 348.882716 -271.011396)
		(width 0.2032)
		(layer "F.Cu")
		(net "GND")
	)
	(segment
		(start 157.708346 -292.516814)
		(end 158.813246 -292.516814)
		(width 0.381)
		(layer "F.Cu")
		(net "GND")
	)
	(segment
		(start 459.559914 -268.71676)
		(end 460.664814 -268.71676)
		(width 0.381)
		(layer "F.Cu")
		(net "GND")
	)
	(segment
		(start 171.562014 -284.866588)
		(end 170.457114 -284.866588)
		(width 0.381)
		(layer "F.Cu")
		(net "GND")
	)
	(segment
		(start 86.375494 -279.428194)
		(end 86.375494 -279.964134)
		(width 0.2032)
		(layer "F.Cu")
		(net "GND")
	)
	(segment
		(start 110.340648 -257.45313)
		(end 110.340648 -257.989324)
		(width 0.254)
		(layer "F.Cu")
		(net "GND")
	)
	(segment
		(start 18.679414 -303.566576)
		(end 19.784314 -303.566576)
		(width 0.381)
		(layer "F.Cu")
		(net "GND")
	)
	(segment
		(start 113.274856 -79.078836)
		(end 113.274856 -79.815436)
		(width 0.3556)
		(layer "F.Cu")
		(net "GND")
	)
	(segment
		(start 210.514946 -242.3668)
		(end 211.619846 -242.3668)
		(width 0.381)
		(layer "F.Cu")
		(net "GND")
	)
	(segment
		(start 202.971146 -281.466798)
		(end 204.076046 -281.466798)
		(width 0.381)
		(layer "F.Cu")
		(net "GND")
	)
	(segment
		(start 262.519414 -272.116804)
		(end 263.624314 -272.116804)
		(width 0.381)
		(layer "F.Cu")
		(net "GND")
	)
	(segment
		(start 112.427512 -338.86013)
		(end 113.068862 -338.86013)
		(width 0.381)
		(layer "F.Cu")
		(net "GND")
	)
	(segment
		(start 425.281344 -367.231676)
		(end 424.957494 -367.231676)
		(width 0.381)
		(layer "F.Cu")
		(net "GND")
	)
	(segment
		(start 377.546362 -253.383796)
		(end 377.546362 -253.919736)
		(width 0.2032)
		(layer "F.Cu")
		(net "GND")
	)
	(segment
		(start 275.268182 -288.266632)
		(end 274.163282 -288.266632)
		(width 0.381)
		(layer "F.Cu")
		(net "GND")
	)
	(segment
		(start 300.238414 -304.416714)
		(end 301.343314 -304.416714)
		(width 0.381)
		(layer "F.Cu")
		(net "GND")
	)
	(segment
		(start 332.696312 -56.908446)
		(end 333.23657 -56.908446)
		(width 0.2032)
		(layer "F.Cu")
		(net "GND")
	)
	(segment
		(start 289.250882 -202.416664)
		(end 290.355782 -202.416664)
		(width 0.381)
		(layer "F.Cu")
		(net "GND")
	)
	(segment
		(start 103.181912 -216.78646)
		(end 103.181912 -216.250774)
		(width 0.254)
		(layer "F.Cu")
		(net "GND")
	)
	(segment
		(start 15.684246 -273.816572)
		(end 16.789146 -273.816572)
		(width 0.381)
		(layer "F.Cu")
		(net "GND")
	)
	(segment
		(start 297.899582 -280.61666)
		(end 299.004482 -280.61666)
		(width 0.381)
		(layer "F.Cu")
		(net "GND")
	)
	(segment
		(start 158.813246 -313.766708)
		(end 160.254188 -313.766708)
		(width 0.381)
		(layer "F.Cu")
		(net "GND")
	)
	(segment
		(start 176.896014 -284.866588)
		(end 178.000914 -284.866588)
		(width 0.381)
		(layer "F.Cu")
		(net "GND")
	)
	(segment
		(start 178.000914 -272.966688)
		(end 179.105814 -272.966688)
		(width 0.381)
		(layer "F.Cu")
		(net "GND")
	)
	(segment
		(start 365.328962 -281.591766)
		(end 365.329216 -281.59202)
		(width 0.254)
		(layer "F.Cu")
		(net "GND")
	)
	(segment
		(start 418.397182 -275.516594)
		(end 417.089082 -275.516594)
		(width 0.381)
		(layer "F.Cu")
		(net "GND")
	)
	(segment
		(start 14.579346 -278.066754)
		(end 15.684246 -278.066754)
		(width 0.381)
		(layer "F.Cu")
		(net "GND")
	)
	(segment
		(start 285.150814 -204.96657)
		(end 286.255714 -204.96657)
		(width 0.381)
		(layer "F.Cu")
		(net "GND")
	)
	(segment
		(start 370.38788 -248.527824)
		(end 370.38788 -247.992138)
		(width 0.2032)
		(layer "F.Cu")
		(net "GND")
	)
	(segment
		(start 369.91798 -220.041978)
		(end 369.918234 -220.041724)
		(width 0.254)
		(layer "F.Cu")
		(net "GND")
	)
	(segment
		(start 425.940982 -249.166634)
		(end 427.045882 -249.166634)
		(width 0.381)
		(layer "F.Cu")
		(net "GND")
	)
	(segment
		(start 116.449094 -284.311598)
		(end 116.449094 -284.847284)
		(width 0.254)
		(layer "F.Cu")
		(net "GND")
	)
	(segment
		(start 199.527414 -245.76659)
		(end 200.632314 -245.76659)
		(width 0.381)
		(layer "F.Cu")
		(net "GND")
	)
	(segment
		(start 335.725262 -270.475456)
		(end 335.725262 -271.011396)
		(width 0.2032)
		(layer "F.Cu")
		(net "GND")
	)
	(segment
		(start 418.397182 -249.166634)
		(end 417.292282 -249.166634)
		(width 0.381)
		(layer "F.Cu")
		(net "GND")
	)
	(segment
		(start 136.655048 -267.755624)
		(end 136.654794 -267.755878)
		(width 0.254)
		(layer "F.Cu")
		(net "GND")
	)
	(segment
		(start 52.082446 -217.716608)
		(end 53.403246 -217.716608)
		(width 0.381)
		(layer "F.Cu")
		(net "GND")
	)
	(segment
		(start 97.653348 -268.034008)
		(end 97.653348 -268.569694)
		(width 0.2032)
		(layer "F.Cu")
		(net "GND")
	)
	(segment
		(start 117.278912 -223.297496)
		(end 117.278912 -222.76181)
		(width 0.254)
		(layer "F.Cu")
		(net "GND")
	)
	(segment
		(start 382.135634 -244.458744)
		(end 382.135634 -243.922804)
		(width 0.2032)
		(layer "F.Cu")
		(net "GND")
	)
	(segment
		(start 133.725412 -365.747808)
		(end 134.42315 -366.445546)
		(width 0.508)
		(layer "F.Cu")
		(net "GND")
	)
	(segment
		(start 367.568734 -214.344758)
		(end 367.568734 -213.732618)
		(width 0.254)
		(layer "F.Cu")
		(net "GND")
	)
	(segment
		(start 429.384714 -307.816758)
		(end 430.489614 -307.816758)
		(width 0.381)
		(layer "F.Cu")
		(net "GND")
	)
	(segment
		(start 365.219234 -220.041724)
		(end 365.219234 -219.506038)
		(width 0.254)
		(layer "F.Cu")
		(net "GND")
	)
	(segment
		(start 57.503314 -204.116686)
		(end 58.608214 -204.116686)
		(width 0.381)
		(layer "F.Cu")
		(net "GND")
	)
	(segment
		(start 88.145366 -245.55069)
		(end 88.145366 -246.08663)
		(width 0.2032)
		(layer "F.Cu")
		(net "GND")
	)
	(segment
		(start 169.352214 -204.116686)
		(end 170.457114 -204.116686)
		(width 0.381)
		(layer "F.Cu")
		(net "GND")
	)
	(segment
		(start 411.958282 -291.666676)
		(end 410.853382 -291.666676)
		(width 0.381)
		(layer "F.Cu")
		(net "GND")
	)
	(segment
		(start 261.285482 -200.716642)
		(end 260.180582 -200.716642)
		(width 0.381)
		(layer "F.Cu")
		(net "GND")
	)
	(segment
		(start 139.624054 -247.042432)
		(end 139.878054 -247.042432)
		(width 0.2032)
		(layer "F.Cu")
		(net "GND")
	)
	(segment
		(start 349.24238 -216.78646)
		(end 349.24238 -216.250774)
		(width 0.254)
		(layer "F.Cu")
		(net "GND")
	)
	(segment
		(start 328.123042 -22.274276)
		(end 328.53122 -21.866098)
		(width 0.3556)
		(layer "F.Cu")
		(net "GND")
	)
	(segment
		(start 312.987182 -272.966688)
		(end 314.307982 -272.966688)
		(width 0.381)
		(layer "F.Cu")
		(net "GND")
	)
	(segment
		(start 367.208562 -281.05608)
		(end 367.208816 -281.056334)
		(width 0.254)
		(layer "F.Cu")
		(net "GND")
	)
	(segment
		(start 104.231694 -289.195002)
		(end 104.231694 -289.807142)
		(width 0.254)
		(layer "F.Cu")
		(net "GND")
	)
	(segment
		(start 11.135614 -306.96662)
		(end 12.240514 -306.96662)
		(width 0.381)
		(layer "F.Cu")
		(net "GND")
	)
	(segment
		(start 414.297114 -304.416714)
		(end 415.402014 -304.416714)
		(width 0.381)
		(layer "F.Cu")
		(net "GND")
	)
	(segment
		(start 56.398414 -213.46668)
		(end 57.503314 -213.46668)
		(width 0.381)
		(layer "F.Cu")
		(net "GND")
	)
	(segment
		(start 136.075166 -249.342148)
		(end 135.610854 -249.073924)
		(width 0.254)
		(layer "F.Cu")
		(net "GND")
	)
	(segment
		(start 35.976814 -294.216582)
		(end 34.871914 -294.216582)
		(width 0.381)
		(layer "F.Cu")
		(net "GND")
	)
	(segment
		(start 409.748482 -241.516662)
		(end 410.853382 -241.516662)
		(width 0.381)
		(layer "F.Cu")
		(net "GND")
	)
	(segment
		(start 23.228046 -285.716726)
		(end 24.332946 -285.716726)
		(width 0.381)
		(layer "F.Cu")
		(net "GND")
	)
	(segment
		(start 208.176114 -245.76659)
		(end 209.281014 -245.76659)
		(width 0.381)
		(layer "F.Cu")
		(net "GND")
	)
	(segment
		(start 23.760938 -176.220882)
		(end 23.760938 -175.83404)
		(width 0.254)
		(layer "F.Cu")
		(net "GND")
	)
	(segment
		(start 341.254334 -220.855794)
		(end 341.254334 -220.319854)
		(width 0.2032)
		(layer "F.Cu")
		(net "GND")
	)
	(segment
		(start 375.666762 -279.428194)
		(end 375.667016 -279.964134)
		(width 0.2032)
		(layer "F.Cu")
		(net "GND")
	)
	(segment
		(start 28.433014 -249.166634)
		(end 27.328114 -249.166634)
		(width 0.381)
		(layer "F.Cu")
		(net "GND")
	)
	(segment
		(start 271.168114 -285.716726)
		(end 270.063214 -285.716726)
		(width 0.381)
		(layer "F.Cu")
		(net "GND")
	)
	(segment
		(start 172.795946 -289.11677)
		(end 173.900846 -289.11677)
		(width 0.381)
		(layer "F.Cu")
		(net "GND")
	)
	(segment
		(start 463.659982 -288.266632)
		(end 462.555082 -288.266632)
		(width 0.381)
		(layer "F.Cu")
		(net "GND")
	)
	(segment
		(start 328.244962 -40.946578)
		(end 328.625708 -41.401746)
		(width 0.2032)
		(layer "F.Cu")
		(net "GND")
	)
	(segment
		(start 427.045882 -282.316682)
		(end 425.940982 -282.316682)
		(width 0.381)
		(layer "F.Cu")
		(net "GND")
	)
	(segment
		(start 106.001312 -220.041978)
		(end 106.001566 -220.041724)
		(width 0.254)
		(layer "F.Cu")
		(net "GND")
	)
	(segment
		(start 367.09858 -226.553268)
		(end 367.09858 -226.017582)
		(width 0.254)
		(layer "F.Cu")
		(net "GND")
	)
	(segment
		(start 304.338482 -286.56661)
		(end 305.443382 -286.56661)
		(width 0.381)
		(layer "F.Cu")
		(net "GND")
	)
	(segment
		(start 349.822516 -284.033468)
		(end 349.822262 -284.033722)
		(width 0.254)
		(layer "F.Cu")
		(net "GND")
	)
	(segment
		(start 420.736014 -223.666558)
		(end 421.840914 -223.666558)
		(width 0.381)
		(layer "F.Cu")
		(net "GND")
	)
	(segment
		(start 385.424934 -228.99497)
		(end 384.485134 -228.45903)
		(width 0.254)
		(layer "F.Cu")
		(net "GND")
	)
	(segment
		(start 375.55678 -226.017582)
		(end 375.557034 -226.017328)
		(width 0.254)
		(layer "F.Cu")
		(net "GND")
	)
	(segment
		(start 209.959956 -38.169342)
		(end 210.594956 -38.169342)
		(width 0.3556)
		(layer "F.Cu")
		(net "GND")
	)
	(segment
		(start 195.427346 -236.416596)
		(end 196.532246 -236.416596)
		(width 0.381)
		(layer "F.Cu")
		(net "GND")
	)
	(segment
		(start 347.003116 -281.869896)
		(end 347.002862 -282.405836)
		(width 0.2032)
		(layer "F.Cu")
		(net "GND")
	)
	(segment
		(start 33.767014 -216.866724)
		(end 34.871914 -216.866724)
		(width 0.381)
		(layer "F.Cu")
		(net "GND")
	)
	(segment
		(start 290.355782 -224.516696)
		(end 291.460682 -224.516696)
		(width 0.381)
		(layer "F.Cu")
		(net "GND")
	)
	(segment
		(start 37.330634 -112.619282)
		(end 37.940234 -112.619282)
		(width 0.3556)
		(layer "F.Cu")
		(net "GND")
	)
	(segment
		(start 458.093318 -379.874018)
		(end 457.7461 -380.221236)
		(width 0.3556)
		(layer "F.Cu")
		(net "GND")
	)
	(segment
		(start 159.91078 -110.9091)
		(end 160.438592 -110.9091)
		(width 0.3556)
		(layer "F.Cu")
		(net "GND")
	)
	(segment
		(start 355.461316 -287.288986)
		(end 355.461062 -287.28924)
		(width 0.254)
		(layer "F.Cu")
		(net "GND")
	)
	(segment
		(start 372.377716 -268.84757)
		(end 372.377462 -269.38351)
		(width 0.254)
		(layer "F.Cu")
		(net "GND")
	)
	(segment
		(start 384.4671 -260.31063)
		(end 384.124962 -260.430772)
		(width 0.088646)
		(layer "F.Cu")
		(net "GND")
	)
	(segment
		(start 195.427346 -206.666592)
		(end 196.532246 -206.666592)
		(width 0.381)
		(layer "F.Cu")
		(net "GND")
	)
	(segment
		(start 199.527414 -238.116618)
		(end 200.632314 -238.116618)
		(width 0.381)
		(layer "F.Cu")
		(net "GND")
	)
	(segment
		(start 261.285482 -244.066568)
		(end 260.180582 -244.066568)
		(width 0.381)
		(layer "F.Cu")
		(net "GND")
	)
	(segment
		(start 378.956316 -270.475456)
		(end 378.956062 -271.011396)
		(width 0.2032)
		(layer "F.Cu")
		(net "GND")
	)
	(segment
		(start 177.108104 -54.299866)
		(end 178.289204 -54.299866)
		(width 0.254)
		(layer "F.Cu")
		(net "GND")
	)
	(segment
		(start 266.619482 -202.416664)
		(end 267.724382 -202.416664)
		(width 0.381)
		(layer "F.Cu")
		(net "GND")
	)
	(segment
		(start 38.315646 -311.216802)
		(end 37.210746 -311.216802)
		(width 0.381)
		(layer "F.Cu")
		(net "GND")
	)
	(segment
		(start 124.437648 -276.986492)
		(end 124.437394 -277.522432)
		(width 0.2032)
		(layer "F.Cu")
		(net "GND")
	)
	(segment
		(start 117.749066 -227.367084)
		(end 117.749066 -226.831144)
		(width 0.2032)
		(layer "F.Cu")
		(net "GND")
	)
	(segment
		(start 271.168114 -298.466764)
		(end 270.063214 -298.466764)
		(width 0.381)
		(layer "F.Cu")
		(net "GND")
	)
	(segment
		(start 421.840914 -295.06672)
		(end 420.736014 -295.06672)
		(width 0.381)
		(layer "F.Cu")
		(net "GND")
	)
	(segment
		(start 285.150814 -246.616728)
		(end 286.255714 -246.616728)
		(width 0.381)
		(layer "F.Cu")
		(net "GND")
	)
	(segment
		(start 197.637146 -279.766776)
		(end 196.532246 -279.766776)
		(width 0.381)
		(layer "F.Cu")
		(net "GND")
	)
	(segment
		(start 411.958282 -308.666642)
		(end 410.853382 -308.666642)
		(width 0.381)
		(layer "F.Cu")
		(net "GND")
	)
	(segment
		(start 111.170466 -225.203512)
		(end 111.170212 -225.203258)
		(width 0.254)
		(layer "F.Cu")
		(net "GND")
	)
	(segment
		(start 109.54893 -54.574948)
		(end 110.15853 -54.574948)
		(width 0.3556)
		(layer "F.Cu")
		(net "GND")
	)
	(segment
		(start 178.590956 -353.634802)
		(end 178.590956 -353.168966)
		(width 0.2032)
		(layer "F.Cu")
		(net "GND")
	)
	(segment
		(start 124.437648 -287.288986)
		(end 124.437394 -287.28924)
		(width 0.254)
		(layer "F.Cu")
		(net "GND")
	)
	(segment
		(start 8.140446 -238.966756)
		(end 9.245346 -238.966756)
		(width 0.381)
		(layer "F.Cu")
		(net "GND")
	)
	(segment
		(start 341.834216 -269.661894)
		(end 341.834216 -270.19758)
		(width 0.2032)
		(layer "F.Cu")
		(net "GND")
	)
	(segment
		(start 293.799514 -283.166566)
		(end 294.904414 -283.166566)
		(width 0.381)
		(layer "F.Cu")
		(net "GND")
	)
	(segment
		(start 23.228046 -309.51678)
		(end 24.332946 -309.51678)
		(width 0.381)
		(layer "F.Cu")
		(net "GND")
	)
	(segment
		(start 88.145366 -226.553268)
		(end 88.145366 -226.017328)
		(width 0.254)
		(layer "F.Cu")
		(net "GND")
	)
	(segment
		(start 92.484448 -283.497782)
		(end 92.484448 -284.033468)
		(width 0.254)
		(layer "F.Cu")
		(net "GND")
	)
	(segment
		(start 97.073466 -220.855794)
		(end 97.073466 -220.319854)
		(width 0.2032)
		(layer "F.Cu")
		(net "GND")
	)
	(segment
		(start 266.619482 -205.816708)
		(end 267.724382 -205.816708)
		(width 0.381)
		(layer "F.Cu")
		(net "GND")
	)
	(segment
		(start 110.551976 -391.556748)
		(end 109.980984 -392.12774)
		(width 0.3556)
		(layer "F.Cu")
		(net "GND")
	)
	(segment
		(start 116.919248 -276.986492)
		(end 116.918994 -277.522432)
		(width 0.2032)
		(layer "F.Cu")
		(net "GND")
	)
	(segment
		(start 30.771846 -216.016586)
		(end 31.876746 -216.016586)
		(width 0.381)
		(layer "F.Cu")
		(net "GND")
	)
	(segment
		(start 178.000914 -200.716642)
		(end 176.896014 -200.716642)
		(width 0.381)
		(layer "F.Cu")
		(net "GND")
	)
	(segment
		(start 65.047114 -194.766692)
		(end 66.152014 -194.766692)
		(width 0.381)
		(layer "F.Cu")
		(net "GND")
	)
	(segment
		(start 301.343314 -236.416596)
		(end 302.664114 -236.416596)
		(width 0.381)
		(layer "F.Cu")
		(net "GND")
	)
	(segment
		(start 95.193866 -214.344758)
		(end 95.193866 -213.732618)
		(width 0.254)
		(layer "F.Cu")
		(net "GND")
	)
	(segment
		(start 52.298346 -260.21665)
		(end 53.403246 -260.21665)
		(width 0.381)
		(layer "F.Cu")
		(net "GND")
	)
	(segment
		(start 429.566832 -8.320024)
		(end 429.566832 -7.215124)
		(width 0.3556)
		(layer "F.Cu")
		(net "GND")
	)
	(segment
		(start 435.823614 -311.216802)
		(end 436.928514 -311.216802)
		(width 0.381)
		(layer "F.Cu")
		(net "GND")
	)
	(segment
		(start 172.503592 -420.97452)
		(end 171.868592 -420.97452)
		(width 0.3556)
		(layer "F.Cu")
		(net "GND")
	)
	(segment
		(start 42.415714 -224.516696)
		(end 41.310814 -224.516696)
		(width 0.381)
		(layer "F.Cu")
		(net "GND")
	)
	(segment
		(start 433.484782 -216.866724)
		(end 434.589682 -216.866724)
		(width 0.381)
		(layer "F.Cu")
		(net "GND")
	)
	(segment
		(start 38.315646 -272.116804)
		(end 37.210746 -272.116804)
		(width 0.381)
		(layer "F.Cu")
		(net "GND")
	)
	(segment
		(start 94.833694 -278.336248)
		(end 94.833948 -278.336502)
		(width 0.2032)
		(layer "F.Cu")
		(net "GND")
	)
	(segment
		(start 214.615014 -306.96662)
		(end 215.719914 -306.96662)
		(width 0.381)
		(layer "F.Cu")
		(net "GND")
	)
	(segment
		(start 52.298346 -306.116736)
		(end 53.403246 -306.116736)
		(width 0.381)
		(layer "F.Cu")
		(net "GND")
	)
	(segment
		(start 346.532962 -264.778236)
		(end 346.532962 -265.314176)
		(width 0.2032)
		(layer "F.Cu")
		(net "GND")
	)
	(segment
		(start 86.735666 -217.600276)
		(end 86.735666 -217.06459)
		(width 0.2032)
		(layer "F.Cu")
		(net "GND")
	)
	(segment
		(start 121.038112 -216.78646)
		(end 121.038112 -216.250774)
		(width 0.254)
		(layer "F.Cu")
		(net "GND")
	)
	(segment
		(start 386.905246 -248.528078)
		(end 387.057646 -248.680478)
		(width 0.2032)
		(layer "F.Cu")
		(net "GND")
	)
	(segment
		(start 436.928514 -261.916672)
		(end 438.033414 -261.916672)
		(width 0.381)
		(layer "F.Cu")
		(net "GND")
	)
	(segment
		(start 459.559914 -289.11677)
		(end 460.664814 -289.11677)
		(width 0.381)
		(layer "F.Cu")
		(net "GND")
	)
	(segment
		(start 349.71228 -245.272306)
		(end 349.71228 -244.73662)
		(width 0.2032)
		(layer "F.Cu")
		(net "GND")
	)
	(segment
		(start 293.799514 -206.666592)
		(end 292.694614 -206.666592)
		(width 0.381)
		(layer "F.Cu")
		(net "GND")
	)
	(segment
		(start 185.544714 -289.966654)
		(end 184.439814 -289.966654)
		(width 0.381)
		(layer "F.Cu")
		(net "GND")
	)
	(segment
		(start 271.168114 -217.716608)
		(end 270.063214 -217.716608)
		(width 0.381)
		(layer "F.Cu")
		(net "GND")
	)
	(segment
		(start 338.904834 -249.341894)
		(end 338.904834 -248.806208)
		(width 0.2032)
		(layer "F.Cu")
		(net "GND")
	)
	(segment
		(start 420.736014 -206.666592)
		(end 421.840914 -206.666592)
		(width 0.381)
		(layer "F.Cu")
		(net "GND")
	)
	(segment
		(start 384.124962 -281.05608)
		(end 384.124962 -281.59202)
		(width 0.254)
		(layer "F.Cu")
		(net "GND")
	)
	(segment
		(start 369.91798 -226.553268)
		(end 369.91798 -226.017582)
		(width 0.254)
		(layer "F.Cu")
		(net "GND")
	)
	(segment
		(start 443.367414 -315.46673)
		(end 444.472314 -315.46673)
		(width 0.381)
		(layer "F.Cu")
		(net "GND")
	)
	(segment
		(start 301.343314 -234.716574)
		(end 302.664114 -234.716574)
		(width 0.381)
		(layer "F.Cu")
		(net "GND")
	)
	(segment
		(start 96.243648 -268.84757)
		(end 96.243648 -269.383256)
		(width 0.2032)
		(layer "F.Cu")
		(net "GND")
	)
	(segment
		(start 432.379882 -204.116686)
		(end 433.484782 -204.116686)
		(width 0.381)
		(layer "F.Cu")
		(net "GND")
	)
	(segment
		(start 266.619482 -245.76659)
		(end 267.724382 -245.76659)
		(width 0.381)
		(layer "F.Cu")
		(net "GND")
	)
	(segment
		(start 452.016114 -212.616796)
		(end 450.911214 -212.616796)
		(width 0.381)
		(layer "F.Cu")
		(net "GND")
	)
	(segment
		(start 180.339746 -240.666778)
		(end 181.444646 -240.666778)
		(width 0.381)
		(layer "F.Cu")
		(net "GND")
	)
	(segment
		(start 356.761034 -229.808532)
		(end 356.761034 -229.272846)
		(width 0.2032)
		(layer "F.Cu")
		(net "GND")
	)
	(segment
		(start 95.69958 -98.367088)
		(end 95.139256 -98.927412)
		(width 0.3556)
		(layer "F.Cu")
		(net "GND")
	)
	(segment
		(start 387.481318 -270.247618)
		(end 387.481318 -270.458438)
		(width 0.254)
		(layer "F.Cu")
		(net "GND")
	)
	(segment
		(start 29.666946 -244.916706)
		(end 30.771846 -244.916706)
		(width 0.381)
		(layer "F.Cu")
		(net "GND")
	)
	(segment
		(start 464.764882 -303.566576)
		(end 463.659982 -303.566576)
		(width 0.381)
		(layer "F.Cu")
		(net "GND")
	)
	(segment
		(start 128.41605 -60.416948)
		(end 129.032 -60.416948)
		(width 0.3556)
		(layer "F.Cu")
		(net "GND")
	)
	(segment
		(start 452.016114 -258.516628)
		(end 450.911214 -258.516628)
		(width 0.381)
		(layer "F.Cu")
		(net "GND")
	)
	(segment
		(start 266.619482 -275.516594)
		(end 267.724382 -275.516594)
		(width 0.381)
		(layer "F.Cu")
		(net "GND")
	)
	(segment
		(start 93.783912 -226.553268)
		(end 93.783912 -226.017582)
		(width 0.254)
		(layer "F.Cu")
		(net "GND")
	)
	(segment
		(start 436.928514 -223.666558)
		(end 438.033414 -223.666558)
		(width 0.381)
		(layer "F.Cu")
		(net "GND")
	)
	(segment
		(start 428.279814 -234.716574)
		(end 429.384714 -234.716574)
		(width 0.381)
		(layer "F.Cu")
		(net "GND")
	)
	(segment
		(start 406.753314 -272.116804)
		(end 405.419814 -272.116804)
		(width 0.381)
		(layer "F.Cu")
		(net "GND")
	)
	(segment
		(start 278.711914 -263.616694)
		(end 279.816814 -263.616694)
		(width 0.381)
		(layer "F.Cu")
		(net "GND")
	)
	(segment
		(start 375.17959 -337.601306)
		(end 374.885966 -337.601306)
		(width 0.2032)
		(layer "F.Cu")
		(net "GND")
	)
	(segment
		(start 435.823614 -225.36658)
		(end 436.928514 -225.36658)
		(width 0.381)
		(layer "F.Cu")
		(net "GND")
	)
	(segment
		(start 187.883546 -295.06672)
		(end 188.988446 -295.06672)
		(width 0.381)
		(layer "F.Cu")
		(net "GND")
	)
	(segment
		(start 408.05227 -285.667196)
		(end 407.780744 -285.667196)
		(width 0.381)
		(layer "F.Cu")
		(net "GND")
	)
	(segment
		(start 202.971146 -292.516814)
		(end 204.076046 -292.516814)
		(width 0.381)
		(layer "F.Cu")
		(net "GND")
	)
	(segment
		(start 120.568212 -228.994716)
		(end 120.568212 -228.45903)
		(width 0.254)
		(layer "F.Cu")
		(net "GND")
	)
	(segment
		(start 152.911556 -38.975284)
		(end 152.075896 -38.975284)
		(width 0.3556)
		(layer "F.Cu")
		(net "GND")
	)
	(segment
		(start 348.30258 -237.947454)
		(end 348.302834 -237.947454)
		(width 0.254)
		(layer "F.Cu")
		(net "GND")
	)
	(segment
		(start 53.403246 -223.666558)
		(end 54.508146 -223.666558)
		(width 0.381)
		(layer "F.Cu")
		(net "GND")
	)
	(segment
		(start 293.799514 -244.916706)
		(end 292.694614 -244.916706)
		(width 0.381)
		(layer "F.Cu")
		(net "GND")
	)
	(segment
		(start 105.061512 -222.76181)
		(end 105.061766 -222.761556)
		(width 0.254)
		(layer "F.Cu")
		(net "GND")
	)
	(segment
		(start 373.67718 -226.017582)
		(end 373.677434 -226.017328)
		(width 0.254)
		(layer "F.Cu")
		(net "GND")
	)
	(segment
		(start 368.618516 -283.497782)
		(end 368.618516 -284.033468)
		(width 0.254)
		(layer "F.Cu")
		(net "GND")
	)
	(segment
		(start 290.355782 -306.96662)
		(end 291.460682 -306.96662)
		(width 0.381)
		(layer "F.Cu")
		(net "GND")
	)
	(segment
		(start 197.41388 -111.324898)
		(end 198.12508 -111.324898)
		(width 0.3556)
		(layer "F.Cu")
		(net "GND")
	)
	(segment
		(start 412.989014 -273.816572)
		(end 414.297114 -273.816572)
		(width 0.381)
		(layer "F.Cu")
		(net "GND")
	)
	(segment
		(start 458.455014 -311.216802)
		(end 459.559914 -311.216802)
		(width 0.381)
		(layer "F.Cu")
		(net "GND")
	)
	(segment
		(start 102.464362 -102.04323)
		(end 101.886766 -102.04323)
		(width 0.3556)
		(layer "F.Cu")
		(net "GND")
	)
	(segment
		(start 351.12198 -220.041978)
		(end 351.122234 -220.041724)
		(width 0.254)
		(layer "F.Cu")
		(net "GND")
	)
	(segment
		(start 20.889214 -210.066636)
		(end 19.784314 -210.066636)
		(width 0.381)
		(layer "F.Cu")
		(net "GND")
	)
	(segment
		(start 157.708346 -315.46673)
		(end 158.813246 -315.46673)
		(width 0.381)
		(layer "F.Cu")
		(net "GND")
	)
	(segment
		(start 466.221064 -116.616734)
		(end 466.85708 -116.616734)
		(width 0.3556)
		(layer "F.Cu")
		(net "GND")
	)
	(segment
		(start 425.940982 -226.216718)
		(end 427.045882 -226.216718)
		(width 0.381)
		(layer "F.Cu")
		(net "GND")
	)
	(segment
		(start 123.027694 -256.807462)
		(end 123.027948 -257.175254)
		(width 0.2032)
		(layer "F.Cu")
		(net "GND")
	)
	(segment
		(start 8.140446 -295.06672)
		(end 9.245346 -295.06672)
		(width 0.381)
		(layer "F.Cu")
		(net "GND")
	)
	(segment
		(start 369.088162 -279.428194)
		(end 369.088416 -279.964134)
		(width 0.254)
		(layer "F.Cu")
		(net "GND")
	)
	(segment
		(start 439.923682 -213.46668)
		(end 441.028582 -213.46668)
		(width 0.381)
		(layer "F.Cu")
		(net "GND")
	)
	(segment
		(start 386.83438 -229.808786)
		(end 387.304534 -230.086662)
		(width 0.254)
		(layer "F.Cu")
		(net "GND")
	)
	(segment
		(start 418.397182 -247.466612)
		(end 417.292282 -247.466612)
		(width 0.381)
		(layer "F.Cu")
		(net "GND")
	)
	(segment
		(start 410.853382 -250.866656)
		(end 411.958282 -250.866656)
		(width 0.381)
		(layer "F.Cu")
		(net "GND")
	)
	(segment
		(start 358.523794 -334.191102)
		(end 358.136952 -333.80426)
		(width 0.2032)
		(layer "F.Cu")
		(net "GND")
	)
	(segment
		(start 133.725666 -245.27256)
		(end 133.725666 -244.73662)
		(width 0.2032)
		(layer "F.Cu")
		(net "GND")
	)
	(segment
		(start 297.899582 -232.166668)
		(end 299.004482 -232.166668)
		(width 0.381)
		(layer "F.Cu")
		(net "GND")
	)
	(segment
		(start 333.26578 -247.714262)
		(end 332.796134 -247.992138)
		(width 0.2032)
		(layer "F.Cu")
		(net "GND")
	)
	(segment
		(start 159.918146 -263.616694)
		(end 158.813246 -263.616694)
		(width 0.381)
		(layer "F.Cu")
		(net "GND")
	)
	(segment
		(start 346.063316 -255.825498)
		(end 346.063316 -256.361184)
		(width 0.2032)
		(layer "F.Cu")
		(net "GND")
	)
	(segment
		(start 214.615014 -222.816674)
		(end 215.719914 -222.816674)
		(width 0.381)
		(layer "F.Cu")
		(net "GND")
	)
	(segment
		(start 16.733774 -76.943204)
		(end 16.733774 -77.578204)
		(width 0.3556)
		(layer "F.Cu")
		(net "GND")
	)
	(segment
		(start 89.555066 -248.528078)
		(end 89.555066 -247.992138)
		(width 0.2032)
		(layer "F.Cu")
		(net "GND")
	)
	(segment
		(start 19.707352 -167.922956)
		(end 19.707352 -167.570658)
		(width 0.3556)
		(layer "F.Cu")
		(net "GND")
	)
	(segment
		(start 254.975614 -260.21665)
		(end 256.080514 -260.21665)
		(width 0.381)
		(layer "F.Cu")
		(net "GND")
	)
	(segment
		(start 337.604862 -255.825498)
		(end 337.604862 -256.361438)
		(width 0.2032)
		(layer "F.Cu")
		(net "GND")
	)
	(segment
		(start 122.558048 -268.84757)
		(end 122.557794 -269.38351)
		(width 0.254)
		(layer "F.Cu")
		(net "GND")
	)
	(segment
		(start 183.861964 -13.599922)
		(end 183.86044 -13.598398)
		(width 0.3556)
		(layer "F.Cu")
		(net "GND")
	)
	(segment
		(start 432.379882 -310.366664)
		(end 433.484782 -310.366664)
		(width 0.381)
		(layer "F.Cu")
		(net "GND")
	)
	(segment
		(start 307.782214 -203.266802)
		(end 308.887114 -203.266802)
		(width 0.381)
		(layer "F.Cu")
		(net "GND")
	)
	(segment
		(start 26.223214 -301.01667)
		(end 27.328114 -301.01667)
		(width 0.381)
		(layer "F.Cu")
		(net "GND")
	)
	(segment
		(start 87.315294 -274.54479)
		(end 86.845394 -274.266914)
		(width 0.2032)
		(layer "F.Cu")
		(net "GND")
	)
	(segment
		(start 92.844366 -236.319568)
		(end 92.844366 -235.783882)
		(width 0.2032)
		(layer "F.Cu")
		(net "GND")
	)
	(segment
		(start 452.016114 -236.416596)
		(end 450.911214 -236.416596)
		(width 0.381)
		(layer "F.Cu")
		(net "GND")
	)
	(segment
		(start 29.666946 -304.416714)
		(end 30.771846 -304.416714)
		(width 0.381)
		(layer "F.Cu")
		(net "GND")
	)
	(segment
		(start 261.285482 -277.216616)
		(end 260.180582 -277.216616)
		(width 0.381)
		(layer "F.Cu")
		(net "GND")
	)
	(segment
		(start 7.035546 -250.016772)
		(end 8.140446 -250.016772)
		(width 0.381)
		(layer "F.Cu")
		(net "GND")
	)
	(segment
		(start 107.521248 -284.033468)
		(end 107.520994 -284.033722)
		(width 0.254)
		(layer "F.Cu")
		(net "GND")
	)
	(segment
		(start 297.41622 -418.62756)
		(end 297.41622 -417.990528)
		(width 0.3556)
		(layer "F.Cu")
		(net "GND")
	)
	(segment
		(start 462.357978 -94.317566)
		(end 462.357978 -94.952566)
		(width 0.3556)
		(layer "F.Cu")
		(net "GND")
	)
	(segment
		(start 363.809534 -214.344758)
		(end 363.809534 -213.732618)
		(width 0.254)
		(layer "F.Cu")
		(net "GND")
	)
	(segment
		(start 38.315646 -246.616728)
		(end 37.210746 -246.616728)
		(width 0.381)
		(layer "F.Cu")
		(net "GND")
	)
	(segment
		(start 358.170734 -238.761524)
		(end 358.17048 -238.76127)
		(width 0.254)
		(layer "F.Cu")
		(net "GND")
	)
	(segment
		(start 449.677282 -299.316648)
		(end 448.572382 -299.316648)
		(width 0.381)
		(layer "F.Cu")
		(net "GND")
	)
	(segment
		(start 58.666888 -8.320024)
		(end 58.666888 -7.215124)
		(width 0.3556)
		(layer "F.Cu")
		(net "GND")
	)
	(segment
		(start 99.532694 -255.011682)
		(end 99.532694 -255.547368)
		(width 0.2032)
		(layer "F.Cu")
		(net "GND")
	)
	(segment
		(start 423.804842 -391.632948)
		(end 423.195242 -391.632948)
		(width 0.3556)
		(layer "F.Cu")
		(net "GND")
	)
	(segment
		(start 256.080514 -313.766708)
		(end 257.185414 -313.766708)
		(width 0.381)
		(layer "F.Cu")
		(net "GND")
	)
	(segment
		(start 267.724382 -235.566712)
		(end 268.829282 -235.566712)
		(width 0.381)
		(layer "F.Cu")
		(net "GND")
	)
	(segment
		(start 307.2384 -28.7528)
		(end 306.5526 -29.4386)
		(width 0.3556)
		(layer "F.Cu")
		(net "GND")
	)
	(segment
		(start 39.394892 -397.82496)
		(end 40.39489 -397.82496)
		(width 0.4572)
		(layer "F.Cu")
		(net "GND")
	)
	(segment
		(start 266.619482 -258.516628)
		(end 267.724382 -258.516628)
		(width 0.381)
		(layer "F.Cu")
		(net "GND")
	)
	(segment
		(start 180.339746 -210.916774)
		(end 181.444646 -210.916774)
		(width 0.381)
		(layer "F.Cu")
		(net "GND")
	)
	(segment
		(start 305.5112 -23.7744)
		(end 305.2572 -24.0284)
		(width 0.3556)
		(layer "F.Cu")
		(net "GND")
	)
	(segment
		(start 374.457976 -337.173316)
		(end 374.457976 -336.741008)
		(width 0.2032)
		(layer "F.Cu")
		(net "GND")
	)
	(segment
		(start 204.076046 -307.816758)
		(end 205.180946 -307.816758)
		(width 0.381)
		(layer "F.Cu")
		(net "GND")
	)
	(segment
		(start 346.359988 -59.721242)
		(end 345.904058 -59.265312)
		(width 0.2032)
		(layer "F.Cu")
		(net "GND")
	)
	(segment
		(start 173.900846 -206.666592)
		(end 172.795946 -206.666592)
		(width 0.381)
		(layer "F.Cu")
		(net "GND")
	)
	(segment
		(start 92.484448 -257.45313)
		(end 92.484448 -257.98907)
		(width 0.2032)
		(layer "F.Cu")
		(net "GND")
	)
	(segment
		(start 382.245362 -284.311598)
		(end 382.245616 -284.847538)
		(width 0.2032)
		(layer "F.Cu")
		(net "GND")
	)
	(segment
		(start 301.343314 -309.51678)
		(end 302.448214 -309.51678)
		(width 0.381)
		(layer "F.Cu")
		(net "GND")
	)
	(segment
		(start 375.666762 -271.289272)
		(end 375.667016 -271.825212)
		(width 0.2032)
		(layer "F.Cu")
		(net "GND")
	)
	(segment
		(start 449.169028 -76.637896)
		(end 449.169028 -75.902566)
		(width 0.254)
		(layer "F.Cu")
		(net "GND")
	)
	(segment
		(start 202.971146 -260.21665)
		(end 204.076046 -260.21665)
		(width 0.381)
		(layer "F.Cu")
		(net "GND")
	)
	(segment
		(start 281.707082 -215.166702)
		(end 282.811982 -215.166702)
		(width 0.381)
		(layer "F.Cu")
		(net "GND")
	)
	(segment
		(start 170.457114 -219.41663)
		(end 169.142664 -219.41663)
		(width 0.381)
		(layer "F.Cu")
		(net "GND")
	)
	(segment
		(start 266.619482 -216.866724)
		(end 267.724382 -216.866724)
		(width 0.381)
		(layer "F.Cu")
		(net "GND")
	)
	(segment
		(start 307.566314 -311.216802)
		(end 308.887114 -311.216802)
		(width 0.381)
		(layer "F.Cu")
		(net "GND")
	)
	(segment
		(start 121.618248 -283.497782)
		(end 121.618248 -284.033468)
		(width 0.254)
		(layer "F.Cu")
		(net "GND")
	)
	(segment
		(start 84.966048 -263.96442)
		(end 84.965794 -264.50036)
		(width 0.254)
		(layer "F.Cu")
		(net "GND")
	)
	(segment
		(start 180.339746 -220.266768)
		(end 181.444646 -220.266768)
		(width 0.381)
		(layer "F.Cu")
		(net "GND")
	)
	(segment
		(start 429.384714 -279.766776)
		(end 430.489614 -279.766776)
		(width 0.381)
		(layer "F.Cu")
		(net "GND")
	)
	(segment
		(start 124.907548 -281.591766)
		(end 124.907548 -281.59202)
		(width 0.254)
		(layer "F.Cu")
		(net "GND")
	)
	(segment
		(start 87.205312 -218.414346)
		(end 87.205312 -217.87866)
		(width 0.2032)
		(layer "F.Cu")
		(net "GND")
	)
	(segment
		(start 262.519414 -285.716726)
		(end 263.624314 -285.716726)
		(width 0.381)
		(layer "F.Cu")
		(net "GND")
	)
	(segment
		(start 27.328114 -272.966688)
		(end 28.433014 -272.966688)
		(width 0.381)
		(layer "F.Cu")
		(net "GND")
	)
	(segment
		(start 347.472762 -253.383796)
		(end 347.472762 -253.919482)
		(width 0.2032)
		(layer "F.Cu")
		(net "GND")
	)
	(segment
		(start 15.684246 -240.666778)
		(end 16.789146 -240.666778)
		(width 0.381)
		(layer "F.Cu")
		(net "GND")
	)
	(segment
		(start 348.412562 -260.430518)
		(end 348.412816 -260.430772)
		(width 0.254)
		(layer "F.Cu")
		(net "GND")
	)
	(segment
		(start 191.983614 -299.316648)
		(end 193.088514 -299.316648)
		(width 0.381)
		(layer "F.Cu")
		(net "GND")
	)
	(segment
		(start 383.545334 -246.364506)
		(end 384.015234 -246.08663)
		(width 0.254)
		(layer "F.Cu")
		(net "GND")
	)
	(segment
		(start 386.474716 -272.103342)
		(end 386.944616 -271.825212)
		(width 0.254)
		(layer "F.Cu")
		(net "GND")
	)
	(segment
		(start 126.946152 -337.601306)
		(end 126.518162 -337.173316)
		(width 0.2032)
		(layer "F.Cu")
		(net "GND")
	)
	(segment
		(start 369.91798 -234.69219)
		(end 369.918234 -234.691936)
		(width 0.254)
		(layer "F.Cu")
		(net "GND")
	)
	(segment
		(start 127.726948 -270.167862)
		(end 127.726948 -270.19758)
		(width 0.2032)
		(layer "F.Cu")
		(net "GND")
	)
	(segment
		(start 26.223214 -271.266666)
		(end 27.328114 -271.266666)
		(width 0.381)
		(layer "F.Cu")
		(net "GND")
	)
	(segment
		(start 164.221414 -272.966688)
		(end 162.913314 -272.966688)
		(width 0.381)
		(layer "F.Cu")
		(net "GND")
	)
	(segment
		(start 345.554554 -45.949108)
		(end 345.553538 -45.949108)
		(width 0.2032)
		(layer "F.Cu")
		(net "GND")
	)
	(segment
		(start 162.913314 -238.116618)
		(end 161.58718 -238.116618)
		(width 0.381)
		(layer "F.Cu")
		(net "GND")
	)
	(segment
		(start 215.719914 -266.1666)
		(end 216.824814 -266.1666)
		(width 0.381)
		(layer "F.Cu")
		(net "GND")
	)
	(segment
		(start 180.339746 -261.916672)
		(end 181.444646 -261.916672)
		(width 0.381)
		(layer "F.Cu")
		(net "GND")
	)
	(segment
		(start 107.056428 -103.593138)
		(end 106.421428 -103.593138)
		(width 0.3556)
		(layer "F.Cu")
		(net "GND")
	)
	(segment
		(start 342.773762 -282.683966)
		(end 342.773762 -283.219906)
		(width 0.2032)
		(layer "F.Cu")
		(net "GND")
	)
	(segment
		(start 364.27918 -223.297496)
		(end 364.27918 -222.76181)
		(width 0.254)
		(layer "F.Cu")
		(net "GND")
	)
	(segment
		(start 327.218548 -58.771028)
		(end 327.240138 -58.609992)
		(width 0.2032)
		(layer "F.Cu")
		(net "GND")
	)
	(segment
		(start 136.655048 -280.242264)
		(end 136.655048 -280.77795)
		(width 0.254)
		(layer "F.Cu")
		(net "GND")
	)
	(segment
		(start 340.401402 -58.850276)
		(end 340.401402 -58.020204)
		(width 0.254)
		(layer "F.Cu")
		(net "GND")
	)
	(segment
		(start 340.78418 -239.57534)
		(end 340.784434 -239.575086)
		(width 0.2032)
		(layer "F.Cu")
		(net "GND")
	)
	(segment
		(start 378.016516 -262.336534)
		(end 378.016262 -262.872474)
		(width 0.2032)
		(layer "F.Cu")
		(net "GND")
	)
	(segment
		(start 278.711914 -206.666592)
		(end 279.816814 -206.666592)
		(width 0.381)
		(layer "F.Cu")
		(net "GND")
	)
	(segment
		(start 367.208562 -286.47517)
		(end 367.208816 -286.475424)
		(width 0.254)
		(layer "F.Cu")
		(net "GND")
	)
	(segment
		(start 372.377716 -284.033468)
		(end 372.377462 -284.033722)
		(width 0.254)
		(layer "F.Cu")
		(net "GND")
	)
	(segment
		(start 439.923682 -267.866622)
		(end 441.028582 -267.866622)
		(width 0.381)
		(layer "F.Cu")
		(net "GND")
	)
	(segment
		(start 443.367414 -296.766742)
		(end 444.472314 -296.766742)
		(width 0.381)
		(layer "F.Cu")
		(net "GND")
	)
	(segment
		(start 178.000914 -207.51673)
		(end 176.896014 -207.51673)
		(width 0.381)
		(layer "F.Cu")
		(net "GND")
	)
	(segment
		(start 286.255714 -197.316598)
		(end 287.360614 -197.316598)
		(width 0.381)
		(layer "F.Cu")
		(net "GND")
	)
	(segment
		(start 429.384714 -290.816792)
		(end 430.489614 -290.816792)
		(width 0.381)
		(layer "F.Cu")
		(net "GND")
	)
	(segment
		(start 118.615968 -37.055552)
		(end 118.915942 -37.355526)
		(width 0.3556)
		(layer "F.Cu")
		(net "GND")
	)
	(segment
		(start 453.121014 -203.266802)
		(end 452.016114 -203.266802)
		(width 0.381)
		(layer "F.Cu")
		(net "GND")
	)
	(segment
		(start 360.367326 -338.86013)
		(end 361.008676 -338.86013)
		(width 0.381)
		(layer "F.Cu")
		(net "GND")
	)
	(segment
		(start 85.324696 -218.41333)
		(end 85.324696 -217.878406)
		(width 0.2032)
		(layer "F.Cu")
		(net "GND")
	)
	(segment
		(start 30.771846 -295.06672)
		(end 31.876746 -295.06672)
		(width 0.381)
		(layer "F.Cu")
		(net "GND")
	)
	(segment
		(start 420.736014 -225.36658)
		(end 421.840914 -225.36658)
		(width 0.381)
		(layer "F.Cu")
		(net "GND")
	)
	(segment
		(start 127.616966 -236.319568)
		(end 127.616966 -235.783882)
		(width 0.2032)
		(layer "F.Cu")
		(net "GND")
	)
	(segment
		(start 122.448066 -248.528078)
		(end 122.447812 -248.527824)
		(width 0.2032)
		(layer "F.Cu")
		(net "GND")
	)
	(segment
		(start 47.311564 -99.79152)
		(end 46.798992 -99.79152)
		(width 0.3556)
		(layer "F.Cu")
		(net "GND")
	)
	(segment
		(start 333.375762 -286.475424)
		(end 333.375762 -285.939484)
		(width 0.254)
		(layer "F.Cu")
		(net "GND")
	)
	(segment
		(start 63.942214 -204.116686)
		(end 65.047114 -204.116686)
		(width 0.381)
		(layer "F.Cu")
		(net "GND")
	)
	(segment
		(start 339.484716 -265.592306)
		(end 339.484462 -265.592306)
		(width 0.254)
		(layer "F.Cu")
		(net "GND")
	)
	(segment
		(start 256.080514 -227.066602)
		(end 257.185414 -227.066602)
		(width 0.381)
		(layer "F.Cu")
		(net "GND")
	)
	(segment
		(start 449.677282 -219.41663)
		(end 448.572382 -219.41663)
		(width 0.381)
		(layer "F.Cu")
		(net "GND")
	)
	(segment
		(start 457.221082 -272.966688)
		(end 456.116182 -272.966688)
		(width 0.381)
		(layer "F.Cu")
		(net "GND")
	)
	(segment
		(start 456.116182 -232.166668)
		(end 455.011282 -232.166668)
		(width 0.381)
		(layer "F.Cu")
		(net "GND")
	)
	(segment
		(start 385.094226 -253.943104)
		(end 385.070858 -253.919736)
		(width 0.2032)
		(layer "F.Cu")
		(net "GND")
	)
	(segment
		(start 170.965622 -335.477612)
		(end 171.981622 -335.477612)
		(width 0.508)
		(layer "F.Cu")
		(net "GND")
	)
	(segment
		(start 363.05363 -363.5121)
		(end 363.05363 -364.15853)
		(width 0.4572)
		(layer "F.Cu")
		(net "GND")
	)
	(segment
		(start 285.689548 -413.63519)
		(end 286.353758 -413.63519)
		(width 0.3556)
		(layer "F.Cu")
		(net "GND")
	)
	(segment
		(start 185.544714 -275.516594)
		(end 184.439814 -275.516594)
		(width 0.381)
		(layer "F.Cu")
		(net "GND")
	)
	(segment
		(start 211.709508 -134.065518)
		(end 212.070188 -134.065518)
		(width 0.254)
		(layer "F.Cu")
		(net "GND")
	)
	(segment
		(start 161.611564 -219.41663)
		(end 162.913314 -219.41663)
		(width 0.381)
		(layer "F.Cu")
		(net "GND")
	)
	(segment
		(start 7.035546 -309.51678)
		(end 8.140446 -309.51678)
		(width 0.381)
		(layer "F.Cu")
		(net "GND")
	)
	(segment
		(start 7.610348 -101.854)
		(end 8.35914 -101.854)
		(width 0.3556)
		(layer "F.Cu")
		(net "GND")
	)
	(segment
		(start 180.339746 -201.56678)
		(end 181.444646 -201.56678)
		(width 0.381)
		(layer "F.Cu")
		(net "GND")
	)
	(segment
		(start 453.121014 -197.316598)
		(end 452.016114 -197.316598)
		(width 0.381)
		(layer "F.Cu")
		(net "GND")
	)
	(segment
		(start 52.298346 -231.316784)
		(end 53.403246 -231.316784)
		(width 0.381)
		(layer "F.Cu")
		(net "GND")
	)
	(segment
		(start 378.956316 -268.84757)
		(end 378.956062 -269.38351)
		(width 0.2032)
		(layer "F.Cu")
		(net "GND")
	)
	(segment
		(start 367.678716 -286.7533)
		(end 367.678716 -287.28924)
		(width 0.254)
		(layer "F.Cu")
		(net "GND")
	)
	(segment
		(start 134.775448 -288.381186)
		(end 134.775448 -288.917126)
		(width 0.254)
		(layer "F.Cu")
		(net "GND")
	)
	(segment
		(start 113.989866 -227.367084)
		(end 113.989866 -226.831144)
		(width 0.2032)
		(layer "F.Cu")
		(net "GND")
	)
	(segment
		(start 369.91798 -228.1809)
		(end 369.91798 -227.64496)
		(width 0.2032)
		(layer "F.Cu")
		(net "GND")
	)
	(segment
		(start 433.484782 -210.066636)
		(end 434.589682 -210.066636)
		(width 0.381)
		(layer "F.Cu")
		(net "GND")
	)
	(segment
		(start 32.947102 -10.16508)
		(end 32.947102 -11.26998)
		(width 0.3556)
		(layer "F.Cu")
		(net "GND")
	)
	(segment
		(start 353.941634 -220.041724)
		(end 353.941634 -219.506038)
		(width 0.254)
		(layer "F.Cu")
		(net "GND")
	)
	(segment
		(start 311.882282 -269.566644)
		(end 312.987182 -269.566644)
		(width 0.381)
		(layer "F.Cu")
		(net "GND")
	)
	(segment
		(start 188.988446 -250.016772)
		(end 187.883546 -250.016772)
		(width 0.381)
		(layer "F.Cu")
		(net "GND")
	)
	(segment
		(start 373.677434 -239.575086)
		(end 373.677434 -239.0394)
		(width 0.2032)
		(layer "F.Cu")
		(net "GND")
	)
	(segment
		(start 128.086612 -245.272306)
		(end 128.086612 -244.73662)
		(width 0.2032)
		(layer "F.Cu")
		(net "GND")
	)
	(segment
		(start 59.842146 -283.166566)
		(end 60.947046 -283.166566)
		(width 0.381)
		(layer "F.Cu")
		(net "GND")
	)
	(segment
		(start 397.803116 -168.106852)
		(end 397.803116 -167.491664)
		(width 0.381)
		(layer "F.Cu")
		(net "GND")
	)
	(segment
		(start 167.461946 -212.616796)
		(end 166.357046 -212.616796)
		(width 0.381)
		(layer "F.Cu")
		(net "GND")
	)
	(segment
		(start 380.835916 -287.288986)
		(end 380.835662 -287.28924)
		(width 0.254)
		(layer "F.Cu")
		(net "GND")
	)
	(segment
		(start 384.015234 -234.15625)
		(end 384.015234 -234.69219)
		(width 0.2032)
		(layer "F.Cu")
		(net "GND")
	)
	(segment
		(start 316.996572 -61.331348)
		(end 316.380622 -61.331348)
		(width 0.381)
		(layer "F.Cu")
		(net "GND")
	)
	(segment
		(start 346.532962 -259.894832)
		(end 346.532962 -260.430772)
		(width 0.2032)
		(layer "F.Cu")
		(net "GND")
	)
	(segment
		(start 119.158512 -220.041978)
		(end 119.158766 -220.041724)
		(width 0.254)
		(layer "F.Cu")
		(net "GND")
	)
	(segment
		(start 101.302312 -222.76181)
		(end 101.302566 -222.761556)
		(width 0.254)
		(layer "F.Cu")
		(net "GND")
	)
	(segment
		(start 161.808414 -233.86669)
		(end 162.913314 -233.86669)
		(width 0.381)
		(layer "F.Cu")
		(net "GND")
	)
	(segment
		(start 419.502082 -211.766658)
		(end 418.397182 -211.766658)
		(width 0.381)
		(layer "F.Cu")
		(net "GND")
	)
	(segment
		(start 54.42458 -145.441924)
		(end 54.42458 -145.1483)
		(width 0.2032)
		(layer "F.Cu")
		(net "GND")
	)
	(segment
		(start 86.265766 -220.041978)
		(end 86.735666 -220.319854)
		(width 0.254)
		(layer "F.Cu")
		(net "GND")
	)
	(segment
		(start 8.140446 -279.766776)
		(end 9.245346 -279.766776)
		(width 0.381)
		(layer "F.Cu")
		(net "GND")
	)
	(segment
		(start 65.047114 -226.216718)
		(end 66.152014 -226.216718)
		(width 0.381)
		(layer "F.Cu")
		(net "GND")
	)
	(segment
		(start 429.384714 -242.3668)
		(end 430.489614 -242.3668)
		(width 0.381)
		(layer "F.Cu")
		(net "GND")
	)
	(segment
		(start 356.76078 -216.78646)
		(end 356.76078 -216.250774)
		(width 0.254)
		(layer "F.Cu")
		(net "GND")
	)
	(segment
		(start 132.895848 -259.081016)
		(end 132.895848 -259.093462)
		(width 0.2032)
		(layer "F.Cu")
		(net "GND")
	)
	(segment
		(start 111.170466 -219.228162)
		(end 111.170466 -218.692476)
		(width 0.2032)
		(layer "F.Cu")
		(net "GND")
	)
	(segment
		(start 300.238414 -281.466798)
		(end 301.343314 -281.466798)
		(width 0.381)
		(layer "F.Cu")
		(net "GND")
	)
	(segment
		(start 380.725934 -232.250488)
		(end 380.72568 -232.250234)
		(width 0.2032)
		(layer "F.Cu")
		(net "GND")
	)
	(segment
		(start 110.230666 -238.761524)
		(end 110.230666 -238.225838)
		(width 0.254)
		(layer "F.Cu")
		(net "GND")
	)
	(segment
		(start 380.725934 -228.45903)
		(end 380.725934 -228.99497)
		(width 0.2032)
		(layer "F.Cu")
		(net "GND")
	)
	(segment
		(start 281.707082 -267.866622)
		(end 282.811982 -267.866622)
		(width 0.381)
		(layer "F.Cu")
		(net "GND")
	)
	(segment
		(start 256.080514 -311.216802)
		(end 257.185414 -311.216802)
		(width 0.381)
		(layer "F.Cu")
		(net "GND")
	)
	(segment
		(start 383.655062 -275.35886)
		(end 383.655062 -275.8948)
		(width 0.254)
		(layer "F.Cu")
		(net "GND")
	)
	(segment
		(start 429.384714 -251.716794)
		(end 430.489614 -251.716794)
		(width 0.381)
		(layer "F.Cu")
		(net "GND")
	)
	(segment
		(start 307.782214 -300.166786)
		(end 308.887114 -300.166786)
		(width 0.381)
		(layer "F.Cu")
		(net "GND")
	)
	(segment
		(start 333.463392 -250.428506)
		(end 333.118714 -250.428506)
		(width 0.2032)
		(layer "F.Cu")
		(net "GND")
	)
	(segment
		(start 429.384714 -227.066602)
		(end 430.489614 -227.066602)
		(width 0.381)
		(layer "F.Cu")
		(net "GND")
	)
	(segment
		(start 125.737366 -249.341894)
		(end 125.737366 -248.806208)
		(width 0.2032)
		(layer "F.Cu")
		(net "GND")
	)
	(segment
		(start 405.89962 -63.754508)
		(end 405.139144 -62.994032)
		(width 0.3556)
		(layer "F.Cu")
		(net "GND")
	)
	(segment
		(start 97.183448 -284.033468)
		(end 97.183194 -284.033722)
		(width 0.254)
		(layer "F.Cu")
		(net "GND")
	)
	(segment
		(start 90.604848 -280.242264)
		(end 90.604848 -280.77795)
		(width 0.254)
		(layer "F.Cu")
		(net "GND")
	)
	(segment
		(start 86.375494 -272.917158)
		(end 87.315294 -273.453098)
		(width 0.2032)
		(layer "F.Cu")
		(net "GND")
	)
	(segment
		(start 358.170734 -243.644928)
		(end 358.170734 -243.108988)
		(width 0.254)
		(layer "F.Cu")
		(net "GND")
	)
	(segment
		(start 342.66378 -236.319822)
		(end 342.664034 -236.319568)
		(width 0.2032)
		(layer "F.Cu")
		(net "GND")
	)
	(segment
		(start 260.180582 -264.466578)
		(end 259.075682 -264.466578)
		(width 0.381)
		(layer "F.Cu")
		(net "GND")
	)
	(segment
		(start 374.726962 -277.800562)
		(end 374.727216 -278.336502)
		(width 0.2032)
		(layer "F.Cu")
		(net "GND")
	)
	(segment
		(start 335.255362 -287.567116)
		(end 335.255616 -287.56737)
		(width 0.254)
		(layer "F.Cu")
		(net "GND")
	)
	(segment
		(start 431.621438 -139.574778)
		(end 431.000154 -139.574778)
		(width 0.381)
		(layer "F.Cu")
		(net "GND")
	)
	(segment
		(start 19.784314 -277.216616)
		(end 20.889214 -277.216616)
		(width 0.381)
		(layer "F.Cu")
		(net "GND")
	)
	(segment
		(start 373.787162 -253.383796)
		(end 373.787162 -253.919482)
		(width 0.2032)
		(layer "F.Cu")
		(net "GND")
	)
	(segment
		(start 405.648414 -261.916672)
		(end 406.753314 -261.916672)
		(width 0.381)
		(layer "F.Cu")
		(net "GND")
	)
	(segment
		(start 300.238414 -265.316716)
		(end 301.343314 -265.316716)
		(width 0.381)
		(layer "F.Cu")
		(net "GND")
	)
	(segment
		(start 325.525384 -343.054432)
		(end 325.922894 -343.451942)
		(width 0.2032)
		(layer "F.Cu")
		(net "GND")
	)
	(segment
		(start 297.899582 -224.516696)
		(end 299.004482 -224.516696)
		(width 0.381)
		(layer "F.Cu")
		(net "GND")
	)
	(segment
		(start 387.625082 -38.265354)
		(end 387.625082 -37.14115)
		(width 0.3556)
		(layer "F.Cu")
		(net "GND")
	)
	(segment
		(start 382.245362 -262.058404)
		(end 382.245616 -262.058658)
		(width 0.2032)
		(layer "F.Cu")
		(net "GND")
	)
	(segment
		(start 89.664794 -288.381186)
		(end 89.664794 -288.917126)
		(width 0.254)
		(layer "F.Cu")
		(net "GND")
	)
	(segment
		(start 353.581462 -268.847824)
		(end 353.581462 -269.38351)
		(width 0.254)
		(layer "F.Cu")
		(net "GND")
	)
	(segment
		(start 337.581748 -42.811446)
		(end 338.120736 -42.811446)
		(width 0.2032)
		(layer "F.Cu")
		(net "GND")
	)
	(segment
		(start 104.591866 -217.600276)
		(end 104.591866 -217.064336)
		(width 0.2032)
		(layer "F.Cu")
		(net "GND")
	)
	(segment
		(start 276.373082 -211.766658)
		(end 275.268182 -211.766658)
		(width 0.381)
		(layer "F.Cu")
		(net "GND")
	)
	(segment
		(start 15.684246 -261.916672)
		(end 16.789146 -261.916672)
		(width 0.381)
		(layer "F.Cu")
		(net "GND")
	)
	(segment
		(start 311.882282 -196.466714)
		(end 312.987182 -196.466714)
		(width 0.381)
		(layer "F.Cu")
		(net "GND")
	)
	(segment
		(start 459.559914 -203.266802)
		(end 458.455014 -203.266802)
		(width 0.381)
		(layer "F.Cu")
		(net "GND")
	)
	(segment
		(start 303.123854 -22.606)
		(end 303.58715 -22.606)
		(width 0.3556)
		(layer "F.Cu")
		(net "GND")
	)
	(segment
		(start 23.946866 -10.16508)
		(end 23.946866 -11.26998)
		(width 0.3556)
		(layer "F.Cu")
		(net "GND")
	)
	(segment
		(start 135.714994 -254.197612)
		(end 135.714994 -254.733552)
		(width 0.2032)
		(layer "F.Cu")
		(net "GND")
	)
	(segment
		(start 441.028582 -308.666642)
		(end 442.133482 -308.666642)
		(width 0.381)
		(layer "F.Cu")
		(net "GND")
	)
	(segment
		(start 59.842146 -289.11677)
		(end 60.947046 -289.11677)
		(width 0.381)
		(layer "F.Cu")
		(net "GND")
	)
	(segment
		(start 185.544714 -196.466714)
		(end 186.649614 -196.466714)
		(width 0.381)
		(layer "F.Cu")
		(net "GND")
	)
	(segment
		(start 99.422966 -233.06405)
		(end 99.422966 -232.528364)
		(width 0.254)
		(layer "F.Cu")
		(net "GND")
	)
	(segment
		(start 102.822248 -280.242264)
		(end 102.822248 -280.778204)
		(width 0.2032)
		(layer "F.Cu")
		(net "GND")
	)
	(segment
		(start 285.150814 -231.316784)
		(end 286.255714 -231.316784)
		(width 0.381)
		(layer "F.Cu")
		(net "GND")
	)
	(segment
		(start 335.615534 -215.436958)
		(end 335.61528 -215.436704)
		(width 0.2032)
		(layer "F.Cu")
		(net "GND")
	)
	(segment
		(start 379.319536 -105.883202)
		(end 380.335536 -105.883202)
		(width 0.3556)
		(layer "F.Cu")
		(net "GND")
	)
	(segment
		(start 463.659982 -262.76681)
		(end 464.764882 -262.76681)
		(width 0.381)
		(layer "F.Cu")
		(net "GND")
	)
	(segment
		(start 161.808414 -282.316682)
		(end 162.913314 -282.316682)
		(width 0.381)
		(layer "F.Cu")
		(net "GND")
	)
	(segment
		(start 355.42855 -404.876)
		(end 354.7364 -404.876)
		(width 0.3556)
		(layer "F.Cu")
		(net "GND")
	)
	(segment
		(start 444.472314 -221.96679)
		(end 443.367414 -221.96679)
		(width 0.381)
		(layer "F.Cu")
		(net "GND")
	)
	(segment
		(start 412.92907 -220.266768)
		(end 414.297114 -220.266768)
		(width 0.381)
		(layer "F.Cu")
		(net "GND")
	)
	(segment
		(start 126.207266 -232.250488)
		(end 126.207012 -232.250234)
		(width 0.2032)
		(layer "F.Cu")
		(net "GND")
	)
	(segment
		(start 59.842146 -295.06672)
		(end 60.947046 -295.06672)
		(width 0.381)
		(layer "F.Cu")
		(net "GND")
	)
	(segment
		(start 188.988446 -204.96657)
		(end 187.883546 -204.96657)
		(width 0.381)
		(layer "F.Cu")
		(net "GND")
	)
	(segment
		(start 357.70058 -226.017582)
		(end 357.700834 -226.017328)
		(width 0.254)
		(layer "F.Cu")
		(net "GND")
	)
	(segment
		(start 327.895458 -37.63518)
		(end 327.217532 -36.957254)
		(width 0.254)
		(layer "F.Cu")
		(net "GND")
	)
	(segment
		(start 354.88118 -222.76181)
		(end 354.881434 -222.761556)
		(width 0.254)
		(layer "F.Cu")
		(net "GND")
	)
	(segment
		(start 441.028582 -215.166702)
		(end 442.133482 -215.166702)
		(width 0.381)
		(layer "F.Cu")
		(net "GND")
	)
	(segment
		(start 286.255714 -204.96657)
		(end 287.360614 -204.96657)
		(width 0.381)
		(layer "F.Cu")
		(net "GND")
	)
	(segment
		(start 159.918146 -260.21665)
		(end 158.813246 -260.21665)
		(width 0.381)
		(layer "F.Cu")
		(net "GND")
	)
	(segment
		(start 157.708346 -225.36658)
		(end 158.813246 -225.36658)
		(width 0.381)
		(layer "F.Cu")
		(net "GND")
	)
	(segment
		(start 134.665466 -220.320108)
		(end 134.665212 -220.319854)
		(width 0.2032)
		(layer "F.Cu")
		(net "GND")
	)
	(segment
		(start 464.764882 -294.216582)
		(end 463.659982 -294.216582)
		(width 0.381)
		(layer "F.Cu")
		(net "GND")
	)
	(segment
		(start 413.408114 -367.06937)
		(end 413.408114 -367.740184)
		(width 0.381)
		(layer "F.Cu")
		(net "GND")
	)
	(segment
		(start 122.917712 -246.08663)
		(end 122.917966 -246.086376)
		(width 0.2032)
		(layer "F.Cu")
		(net "GND")
	)
	(segment
		(start 449.52666 -49.476406)
		(end 450.441568 -49.476406)
		(width 0.508)
		(layer "F.Cu")
		(net "GND")
	)
	(segment
		(start 196.532246 -240.666778)
		(end 197.637146 -240.666778)
		(width 0.381)
		(layer "F.Cu")
		(net "GND")
	)
	(segment
		(start 254.975614 -210.916774)
		(end 256.080514 -210.916774)
		(width 0.381)
		(layer "F.Cu")
		(net "GND")
	)
	(segment
		(start 118.671594 -93.004132)
		(end 119.33682 -93.004132)
		(width 0.3556)
		(layer "F.Cu")
		(net "GND")
	)
	(segment
		(start 282.811982 -219.41663)
		(end 283.916882 -219.41663)
		(width 0.381)
		(layer "F.Cu")
		(net "GND")
	)
	(segment
		(start 439.923682 -284.866588)
		(end 441.028582 -284.866588)
		(width 0.381)
		(layer "F.Cu")
		(net "GND")
	)
	(segment
		(start 91.544648 -254.197612)
		(end 91.544648 -254.733552)
		(width 0.2032)
		(layer "F.Cu")
		(net "GND")
	)
	(segment
		(start 256.134108 -51.36642)
		(end 255.261618 -51.36642)
		(width 0.254)
		(layer "F.Cu")
		(net "GND")
	)
	(segment
		(start 448.572382 -275.516594)
		(end 447.467482 -275.516594)
		(width 0.381)
		(layer "F.Cu")
		(net "GND")
	)
	(segment
		(start 423.823892 -397.651478)
		(end 423.214292 -397.651478)
		(width 0.381)
		(layer "F.Cu")
		(net "GND")
	)
	(segment
		(start 89.664794 -254.197612)
		(end 89.664794 -254.733552)
		(width 0.2032)
		(layer "F.Cu")
		(net "GND")
	)
	(segment
		(start 188.988446 -295.06672)
		(end 190.093346 -295.06672)
		(width 0.381)
		(layer "F.Cu")
		(net "GND")
	)
	(segment
		(start 170.457114 -297.616626)
		(end 169.352214 -297.616626)
		(width 0.381)
		(layer "F.Cu")
		(net "GND")
	)
	(segment
		(start 371.327934 -235.506006)
		(end 371.32768 -235.505752)
		(width 0.2032)
		(layer "F.Cu")
		(net "GND")
	)
	(segment
		(start 336.779108 -15.819628)
		(end 337.845908 -15.819628)
		(width 0.3556)
		(layer "F.Cu")
		(net "GND")
	)
	(segment
		(start 214.615014 -301.01667)
		(end 215.719914 -301.01667)
		(width 0.381)
		(layer "F.Cu")
		(net "GND")
	)
	(segment
		(start 165.252146 -307.816758)
		(end 166.357046 -307.816758)
		(width 0.381)
		(layer "F.Cu")
		(net "GND")
	)
	(segment
		(start 240.50371 -248.011188)
		(end 240.60785 -248.115328)
		(width 0.3556)
		(layer "F.Cu")
		(net "GND")
	)
	(segment
		(start 357.186992 -392.04265)
		(end 356.54996 -392.04265)
		(width 0.3556)
		(layer "F.Cu")
		(net "GND")
	)
	(segment
		(start 104.42575 -410.2608)
		(end 104.0384 -410.2608)
		(width 0.3556)
		(layer "F.Cu")
		(net "GND")
	)
	(segment
		(start 355.461316 -280.77795)
		(end 355.461062 -280.778204)
		(width 0.254)
		(layer "F.Cu")
		(net "GND")
	)
	(segment
		(start 336.49285 -42.811446)
		(end 335.67878 -43.281346)
		(width 0.2032)
		(layer "F.Cu")
		(net "GND")
	)
	(segment
		(start 90.494866 -245.27256)
		(end 90.494866 -244.73662)
		(width 0.2032)
		(layer "F.Cu")
		(net "GND")
	)
	(segment
		(start 120.678448 -268.84757)
		(end 120.678194 -269.38351)
		(width 0.254)
		(layer "F.Cu")
		(net "GND")
	)
	(segment
		(start 207.071214 -301.01667)
		(end 208.176114 -301.01667)
		(width 0.381)
		(layer "F.Cu")
		(net "GND")
	)
	(segment
		(start 343.243662 -267.220192)
		(end 343.243662 -267.755878)
		(width 0.2032)
		(layer "F.Cu")
		(net "GND")
	)
	(segment
		(start 456.116182 -275.516594)
		(end 455.011282 -275.516594)
		(width 0.381)
		(layer "F.Cu")
		(net "GND")
	)
	(segment
		(start 382.605534 -220.320108)
		(end 382.60528 -220.319854)
		(width 0.2032)
		(layer "F.Cu")
		(net "GND")
	)
	(segment
		(start 385.534662 -286.7533)
		(end 385.56946 -286.788098)
		(width 0.254)
		(layer "F.Cu")
		(net "GND")
	)
	(segment
		(start 125.737112 -229.808786)
		(end 125.737366 -229.808532)
		(width 0.2032)
		(layer "F.Cu")
		(net "GND")
	)
	(segment
		(start 199.527414 -226.216718)
		(end 200.632314 -226.216718)
		(width 0.381)
		(layer "F.Cu")
		(net "GND")
	)
	(segment
		(start 311.666382 -235.566712)
		(end 312.987182 -235.566712)
		(width 0.381)
		(layer "F.Cu")
		(net "GND")
	)
	(segment
		(start 65.047114 -215.166702)
		(end 66.152014 -215.166702)
		(width 0.381)
		(layer "F.Cu")
		(net "GND")
	)
	(segment
		(start 296.794682 -202.416664)
		(end 297.899582 -202.416664)
		(width 0.381)
		(layer "F.Cu")
		(net "GND")
	)
	(segment
		(start 453.121014 -246.616728)
		(end 452.016114 -246.616728)
		(width 0.381)
		(layer "F.Cu")
		(net "GND")
	)
	(segment
		(start 89.555066 -235.506006)
		(end 89.554812 -235.505752)
		(width 0.2032)
		(layer "F.Cu")
		(net "GND")
	)
	(segment
		(start 65.047114 -204.116686)
		(end 66.152014 -204.116686)
		(width 0.381)
		(layer "F.Cu")
		(net "GND")
	)
	(segment
		(start 436.928514 -229.616762)
		(end 438.033414 -229.616762)
		(width 0.381)
		(layer "F.Cu")
		(net "GND")
	)
	(segment
		(start 135.135112 -216.78646)
		(end 135.135112 -216.250774)
		(width 0.254)
		(layer "F.Cu")
		(net "GND")
	)
	(segment
		(start 212.44306 -68.86194)
		(end 212.44306 -69.157088)
		(width 0.3556)
		(layer "F.Cu")
		(net "GND")
	)
	(segment
		(start 169.352214 -264.466578)
		(end 170.457114 -264.466578)
		(width 0.381)
		(layer "F.Cu")
		(net "GND")
	)
	(segment
		(start 30.771846 -279.766776)
		(end 31.876746 -279.766776)
		(width 0.381)
		(layer "F.Cu")
		(net "GND")
	)
	(segment
		(start 170.457114 -277.216616)
		(end 171.562014 -277.216616)
		(width 0.381)
		(layer "F.Cu")
		(net "GND")
	)
	(segment
		(start 94.254066 -237.133892)
		(end 94.254066 -236.597952)
		(width 0.2032)
		(layer "F.Cu")
		(net "GND")
	)
	(segment
		(start 215.719914 -261.066788)
		(end 216.824814 -261.066788)
		(width 0.381)
		(layer "F.Cu")
		(net "GND")
	)
	(segment
		(start 429.384714 -214.316564)
		(end 430.489614 -214.316564)
		(width 0.381)
		(layer "F.Cu")
		(net "GND")
	)
	(segment
		(start 159.918146 -287.416748)
		(end 158.813246 -287.416748)
		(width 0.381)
		(layer "F.Cu")
		(net "GND")
	)
	(segment
		(start 297.899582 -233.86669)
		(end 299.004482 -233.86669)
		(width 0.381)
		(layer "F.Cu")
		(net "GND")
	)
	(segment
		(start 136.545066 -220.855794)
		(end 136.545066 -220.319854)
		(width 0.2032)
		(layer "F.Cu")
		(net "GND")
	)
	(segment
		(start 301.343314 -285.716726)
		(end 302.448214 -285.716726)
		(width 0.381)
		(layer "F.Cu")
		(net "GND")
	)
	(segment
		(start 181.444646 -231.316784)
		(end 182.549546 -231.316784)
		(width 0.381)
		(layer "F.Cu")
		(net "GND")
	)
	(segment
		(start 305.443382 -316.316614)
		(end 306.548282 -316.316614)
		(width 0.381)
		(layer "F.Cu")
		(net "GND")
	)
	(segment
		(start 384.485134 -234.97032)
		(end 384.48488 -234.970066)
		(width 0.2032)
		(layer "F.Cu")
		(net "GND")
	)
	(segment
		(start 342.664034 -231.436164)
		(end 342.664034 -230.900478)
		(width 0.2032)
		(layer "F.Cu")
		(net "GND")
	)
	(segment
		(start 96.603566 -220.041724)
		(end 96.603566 -219.506038)
		(width 0.254)
		(layer "F.Cu")
		(net "GND")
	)
	(segment
		(start 185.663078 -17.655032)
		(end 185.663078 -16.551148)
		(width 0.3556)
		(layer "F.Cu")
		(net "GND")
	)
	(segment
		(start 170.955716 -116.975382)
		(end 170.555666 -117.375432)
		(width 0.3556)
		(layer "F.Cu")
		(net "GND")
	)
	(segment
		(start 409.748482 -269.566644)
		(end 410.853382 -269.566644)
		(width 0.381)
		(layer "F.Cu")
		(net "GND")
	)
	(segment
		(start 38.315646 -281.466798)
		(end 37.210746 -281.466798)
		(width 0.381)
		(layer "F.Cu")
		(net "GND")
	)
	(segment
		(start 86.265766 -231.436418)
		(end 86.735666 -231.714548)
		(width 0.2032)
		(layer "F.Cu")
		(net "GND")
	)
	(segment
		(start 350.294956 -339.294724)
		(end 350.294956 -338.690712)
		(width 0.381)
		(layer "F.Cu")
		(net "GND")
	)
	(segment
		(start 432.379882 -249.166634)
		(end 433.484782 -249.166634)
		(width 0.381)
		(layer "F.Cu")
		(net "GND")
	)
	(segment
		(start 346.423234 -220.041724)
		(end 346.423234 -219.506038)
		(width 0.254)
		(layer "F.Cu")
		(net "GND")
	)
	(segment
		(start 370.85778 -229.808786)
		(end 370.85778 -229.272846)
		(width 0.254)
		(layer "F.Cu")
		(net "GND")
	)
	(segment
		(start 402.046948 -11.26998)
		(end 402.046948 -12.37488)
		(width 0.3556)
		(layer "F.Cu")
		(net "GND")
	)
	(segment
		(start 372.73738 -222.76181)
		(end 372.737634 -222.761556)
		(width 0.254)
		(layer "F.Cu")
		(net "GND")
	)
	(segment
		(start 254.975614 -283.166566)
		(end 256.080514 -283.166566)
		(width 0.381)
		(layer "F.Cu")
		(net "GND")
	)
	(segment
		(start 22.123146 -251.716794)
		(end 23.228046 -251.716794)
		(width 0.381)
		(layer "F.Cu")
		(net "GND")
	)
	(segment
		(start 8.140446 -206.666592)
		(end 9.245346 -206.666592)
		(width 0.381)
		(layer "F.Cu")
		(net "GND")
	)
	(segment
		(start 352.171762 -289.195002)
		(end 352.171762 -289.807142)
		(width 0.254)
		(layer "F.Cu")
		(net "GND")
	)
	(segment
		(start 86.735666 -217.06459)
		(end 86.735412 -217.064336)
		(width 0.2032)
		(layer "F.Cu")
		(net "GND")
	)
	(segment
		(start 165.252146 -234.716574)
		(end 166.357046 -234.716574)
		(width 0.381)
		(layer "F.Cu")
		(net "GND")
	)
	(segment
		(start 95.303848 -257.988816)
		(end 95.303594 -257.98907)
		(width 0.2032)
		(layer "F.Cu")
		(net "GND")
	)
	(segment
		(start 128.666494 -274.54479)
		(end 128.666748 -275.08073)
		(width 0.2032)
		(layer "F.Cu")
		(net "GND")
	)
	(segment
		(start 368.97818 -220.041978)
		(end 368.978434 -220.041724)
		(width 0.254)
		(layer "F.Cu")
		(net "GND")
	)
	(segment
		(start 340.784434 -220.041724)
		(end 340.784434 -219.506038)
		(width 0.254)
		(layer "F.Cu")
		(net "GND")
	)
	(segment
		(start 207.071214 -245.76659)
		(end 208.176114 -245.76659)
		(width 0.381)
		(layer "F.Cu")
		(net "GND")
	)
	(segment
		(start 90.964512 -222.76181)
		(end 90.964766 -222.761556)
		(width 0.254)
		(layer "F.Cu")
		(net "GND")
	)
	(segment
		(start 215.719914 -239.81664)
		(end 216.824814 -239.81664)
		(width 0.381)
		(layer "F.Cu")
		(net "GND")
	)
	(segment
		(start 347.942916 -284.033468)
		(end 347.942662 -284.033722)
		(width 0.254)
		(layer "F.Cu")
		(net "GND")
	)
	(segment
		(start 443.367414 -313.766708)
		(end 444.472314 -313.766708)
		(width 0.381)
		(layer "F.Cu")
		(net "GND")
	)
	(segment
		(start 337.699858 -46.049946)
		(end 337.299808 -46.449996)
		(width 0.2032)
		(layer "F.Cu")
		(net "GND")
	)
	(segment
		(start 164.018214 -226.216718)
		(end 162.913314 -226.216718)
		(width 0.381)
		(layer "F.Cu")
		(net "GND")
	)
	(segment
		(start 26.223214 -294.216582)
		(end 27.328114 -294.216582)
		(width 0.381)
		(layer "F.Cu")
		(net "GND")
	)
	(segment
		(start 199.527414 -232.166668)
		(end 200.632314 -232.166668)
		(width 0.381)
		(layer "F.Cu")
		(net "GND")
	)
	(segment
		(start 124.327412 -246.900192)
		(end 124.327412 -246.364506)
		(width 0.2032)
		(layer "F.Cu")
		(net "GND")
	)
	(segment
		(start 200.632314 -267.866622)
		(end 201.737214 -267.866622)
		(width 0.381)
		(layer "F.Cu")
		(net "GND")
	)
	(segment
		(start 285.458916 -362.184696)
		(end 285.664402 -362.390182)
		(width 0.2032)
		(layer "F.Cu")
		(net "GND")
	)
	(segment
		(start 96.133666 -228.99497)
		(end 96.133412 -228.994716)
		(width 0.2032)
		(layer "F.Cu")
		(net "GND")
	)
	(segment
		(start 8.140446 -276.366732)
		(end 9.245346 -276.366732)
		(width 0.381)
		(layer "F.Cu")
		(net "GND")
	)
	(segment
		(start 173.900846 -199.01662)
		(end 172.795946 -199.01662)
		(width 0.381)
		(layer "F.Cu")
		(net "GND")
	)
	(segment
		(start 425.940982 -228.766624)
		(end 427.045882 -228.766624)
		(width 0.381)
		(layer "F.Cu")
		(net "GND")
	)
	(segment
		(start 213.1568 -109.26699)
		(end 213.1568 -110.3122)
		(width 0.3556)
		(layer "F.Cu")
		(net "GND")
	)
	(segment
		(start 193.088514 -314.616592)
		(end 194.193414 -314.616592)
		(width 0.381)
		(layer "F.Cu")
		(net "GND")
	)
	(segment
		(start 301.343314 -315.46673)
		(end 302.448214 -315.46673)
		(width 0.381)
		(layer "F.Cu")
		(net "GND")
	)
	(segment
		(start 277.607014 -223.666558)
		(end 278.711914 -223.666558)
		(width 0.381)
		(layer "F.Cu")
		(net "GND")
	)
	(segment
		(start 193.088514 -196.466714)
		(end 191.983614 -196.466714)
		(width 0.381)
		(layer "F.Cu")
		(net "GND")
	)
	(segment
		(start 193.088514 -216.866724)
		(end 191.983614 -216.866724)
		(width 0.381)
		(layer "F.Cu")
		(net "GND")
	)
	(segment
		(start 180.339746 -225.36658)
		(end 181.444646 -225.36658)
		(width 0.381)
		(layer "F.Cu")
		(net "GND")
	)
	(segment
		(start 345.554554 -56.95442)
		(end 345.554554 -55.953914)
		(width 0.2032)
		(layer "F.Cu")
		(net "GND")
	)
	(segment
		(start 370.85778 -226.553268)
		(end 370.85778 -226.017582)
		(width 0.254)
		(layer "F.Cu")
		(net "GND")
	)
	(segment
		(start 348.412562 -255.547368)
		(end 348.412816 -255.547622)
		(width 0.2032)
		(layer "F.Cu")
		(net "GND")
	)
	(segment
		(start 184.439814 -198.166736)
		(end 185.544714 -198.166736)
		(width 0.381)
		(layer "F.Cu")
		(net "GND")
	)
	(segment
		(start 307.361336 -58.03773)
		(end 307.361336 -56.987948)
		(width 0.3556)
		(layer "F.Cu")
		(net "GND")
	)
	(segment
		(start 464.764882 -288.266632)
		(end 463.659982 -288.266632)
		(width 0.381)
		(layer "F.Cu")
		(net "GND")
	)
	(segment
		(start 34.871914 -213.46668)
		(end 35.976814 -213.46668)
		(width 0.381)
		(layer "F.Cu")
		(net "GND")
	)
	(segment
		(start 350.652334 -231.714802)
		(end 350.65208 -231.714548)
		(width 0.2032)
		(layer "F.Cu")
		(net "GND")
	)
	(segment
		(start 175.005746 -240.666778)
		(end 173.900846 -240.666778)
		(width 0.381)
		(layer "F.Cu")
		(net "GND")
	)
	(segment
		(start 34.871914 -262.76681)
		(end 35.976814 -262.76681)
		(width 0.381)
		(layer "F.Cu")
		(net "GND")
	)
	(segment
		(start 130.076448 -284.033468)
		(end 130.076194 -284.033722)
		(width 0.254)
		(layer "F.Cu")
		(net "GND")
	)
	(segment
		(start 34.871914 -215.166702)
		(end 35.976814 -215.166702)
		(width 0.381)
		(layer "F.Cu")
		(net "GND")
	)
	(segment
		(start 52.298346 -317.166752)
		(end 53.403246 -317.166752)
		(width 0.381)
		(layer "F.Cu")
		(net "GND")
	)
	(segment
		(start 365.810546 -56.583834)
		(end 364.841282 -56.583834)
		(width 0.3556)
		(layer "F.Cu")
		(net "GND")
	)
	(segment
		(start 304.338482 -204.116686)
		(end 305.443382 -204.116686)
		(width 0.381)
		(layer "F.Cu")
		(net "GND")
	)
	(segment
		(start 134.305548 -281.591766)
		(end 134.305548 -281.59202)
		(width 0.254)
		(layer "F.Cu")
		(net "GND")
	)
	(segment
		(start 368.75212 -104.266238)
		(end 368.121184 -104.266238)
		(width 0.3556)
		(layer "F.Cu")
		(net "GND")
	)
	(segment
		(start 26.223214 -299.316648)
		(end 27.328114 -299.316648)
		(width 0.381)
		(layer "F.Cu")
		(net "GND")
	)
	(segment
		(start 405.513794 -285.742126)
		(end 405.539194 -285.716726)
		(width 0.381)
		(layer "F.Cu")
		(net "GND")
	)
	(segment
		(start 335.399126 -39.443152)
		(end 335.899252 -39.295324)
		(width 0.2032)
		(layer "F.Cu")
		(net "GND")
	)
	(segment
		(start 12.240514 -215.166702)
		(end 13.345414 -215.166702)
		(width 0.381)
		(layer "F.Cu")
		(net "GND")
	)
	(segment
		(start 91.434666 -248.528078)
		(end 91.434666 -247.992138)
		(width 0.2032)
		(layer "F.Cu")
		(net "GND")
	)
	(segment
		(start 186.649614 -312.91657)
		(end 185.544714 -312.91657)
		(width 0.381)
		(layer "F.Cu")
		(net "GND")
	)
	(segment
		(start 215.719914 -216.866724)
		(end 216.824814 -216.866724)
		(width 0.381)
		(layer "F.Cu")
		(net "GND")
	)
	(segment
		(start 86.265766 -249.342148)
		(end 86.265766 -248.806208)
		(width 0.2032)
		(layer "F.Cu")
		(net "GND")
	)
	(segment
		(start 178.9557 -115.375436)
		(end 179.35575 -115.775486)
		(width 0.3556)
		(layer "F.Cu")
		(net "GND")
	)
	(segment
		(start 48.854614 -207.51673)
		(end 49.959514 -207.51673)
		(width 0.381)
		(layer "F.Cu")
		(net "GND")
	)
	(segment
		(start 11.135614 -247.466612)
		(end 12.240514 -247.466612)
		(width 0.381)
		(layer "F.Cu")
		(net "GND")
	)
	(segment
		(start 349.822516 -276.986492)
		(end 349.822516 -277.522432)
		(width 0.254)
		(layer "F.Cu")
		(net "GND")
	)
	(segment
		(start 63.726314 -272.966688)
		(end 65.047114 -272.966688)
		(width 0.381)
		(layer "F.Cu")
		(net "GND")
	)
	(segment
		(start 41.324022 -358.528366)
		(end 41.324022 -358.564942)
		(width 0.381)
		(layer "F.Cu")
		(net "GND")
	)
	(segment
		(start 359.11028 -233.877866)
		(end 359.11028 -233.34218)
		(width 0.2032)
		(layer "F.Cu")
		(net "GND")
	)
	(segment
		(start 420.736014 -210.916774)
		(end 421.840914 -210.916774)
		(width 0.381)
		(layer "F.Cu")
		(net "GND")
	)
	(segment
		(start 211.619846 -199.01662)
		(end 212.724746 -199.01662)
		(width 0.381)
		(layer "F.Cu")
		(net "GND")
	)
	(segment
		(start 193.088514 -262.76681)
		(end 191.983614 -262.76681)
		(width 0.381)
		(layer "F.Cu")
		(net "GND")
	)
	(segment
		(start 129.136648 -254.733298)
		(end 129.136394 -254.733552)
		(width 0.254)
		(layer "F.Cu")
		(net "GND")
	)
	(segment
		(start 338.90458 -226.553268)
		(end 338.90458 -226.017328)
		(width 0.254)
		(layer "F.Cu")
		(net "GND")
	)
	(segment
		(start 286.255714 -199.01662)
		(end 287.360614 -199.01662)
		(width 0.381)
		(layer "F.Cu")
		(net "GND")
	)
	(segment
		(start 343.006934 -54.088792)
		(end 343.005156 -54.089046)
		(width 0.2032)
		(layer "F.Cu")
		(net "GND")
	)
	(segment
		(start 260.180582 -207.51673)
		(end 259.075682 -207.51673)
		(width 0.381)
		(layer "F.Cu")
		(net "GND")
	)
	(segment
		(start 371.189758 -360.132376)
		(end 370.878862 -360.443272)
		(width 0.3556)
		(layer "F.Cu")
		(net "GND")
	)
	(segment
		(start 419.502082 -264.466578)
		(end 418.397182 -264.466578)
		(width 0.381)
		(layer "F.Cu")
		(net "GND")
	)
	(segment
		(start 347.472762 -259.894832)
		(end 347.472762 -260.430518)
		(width 0.2032)
		(layer "F.Cu")
		(net "GND")
	)
	(segment
		(start 443.367414 -231.316784)
		(end 444.472314 -231.316784)
		(width 0.381)
		(layer "F.Cu")
		(net "GND")
	)
	(segment
		(start 308.760622 -435.663848)
		(end 309.313326 -436.216552)
		(width 0.3556)
		(layer "F.Cu")
		(net "GND")
	)
	(segment
		(start 49.959514 -316.316614)
		(end 51.064414 -316.316614)
		(width 0.381)
		(layer "F.Cu")
		(net "GND")
	)
	(segment
		(start 462.555082 -235.566712)
		(end 463.659982 -235.566712)
		(width 0.381)
		(layer "F.Cu")
		(net "GND")
	)
	(segment
		(start 193.088514 -207.51673)
		(end 191.983614 -207.51673)
		(width 0.381)
		(layer "F.Cu")
		(net "GND")
	)
	(segment
		(start 88.725248 -276.986492)
		(end 88.255094 -276.708616)
		(width 0.254)
		(layer "F.Cu")
		(net "GND")
	)
	(segment
		(start 20.024852 -56.999886)
		(end 21.83384 -56.999886)
		(width 0.3556)
		(layer "F.Cu")
		(net "GND")
	)
	(segment
		(start 369.448334 -217.600276)
		(end 369.448334 -217.064336)
		(width 0.254)
		(layer "F.Cu")
		(net "GND")
	)
	(segment
		(start 344.07348 -230.622348)
		(end 344.07348 -230.086662)
		(width 0.2032)
		(layer "F.Cu")
		(net "GND")
	)
	(segment
		(start 132.425948 -281.591766)
		(end 132.425948 -281.59202)
		(width 0.254)
		(layer "F.Cu")
		(net "GND")
	)
	(segment
		(start 462.555082 -244.066568)
		(end 463.659982 -244.066568)
		(width 0.381)
		(layer "F.Cu")
		(net "GND")
	)
	(segment
		(start 296.794682 -244.066568)
		(end 297.899582 -244.066568)
		(width 0.381)
		(layer "F.Cu")
		(net "GND")
	)
	(segment
		(start 182.549546 -292.516814)
		(end 181.444646 -292.516814)
		(width 0.381)
		(layer "F.Cu")
		(net "GND")
	)
	(segment
		(start 407.731214 -285.716726)
		(end 406.753314 -285.716726)
		(width 0.381)
		(layer "F.Cu")
		(net "GND")
	)
	(segment
		(start 271.168114 -250.016772)
		(end 270.063214 -250.016772)
		(width 0.381)
		(layer "F.Cu")
		(net "GND")
	)
	(segment
		(start 181.444646 -248.31675)
		(end 182.549546 -248.31675)
		(width 0.381)
		(layer "F.Cu")
		(net "GND")
	)
	(segment
		(start 424.836082 -204.116686)
		(end 425.940982 -204.116686)
		(width 0.381)
		(layer "F.Cu")
		(net "GND")
	)
	(segment
		(start 94.723966 -236.319568)
		(end 94.723966 -235.783882)
		(width 0.2032)
		(layer "F.Cu")
		(net "GND")
	)
	(segment
		(start 117.859048 -281.869896)
		(end 117.859048 -282.405836)
		(width 0.254)
		(layer "F.Cu")
		(net "GND")
	)
	(segment
		(start 296.794682 -198.166736)
		(end 297.899582 -198.166736)
		(width 0.381)
		(layer "F.Cu")
		(net "GND")
	)
	(segment
		(start 407.780744 -285.667196)
		(end 407.731214 -285.716726)
		(width 0.381)
		(layer "F.Cu")
		(net "GND")
	)
	(segment
		(start 126.960122 -338.951316)
		(end 126.646178 -339.26526)
		(width 0.1778)
		(layer "F.Cu")
		(net "GND")
	)
	(segment
		(start 432.644042 -402.290534)
		(end 433.253642 -402.290534)
		(width 0.381)
		(layer "F.Cu")
		(net "GND")
	)
	(segment
		(start 386.02412 -283.200602)
		(end 386.004816 -283.219906)
		(width 0.254)
		(layer "F.Cu")
		(net "GND")
	)
	(segment
		(start 311.427622 -38.809168)
		(end 311.509664 -38.89121)
		(width 0.3556)
		(layer "F.Cu")
		(net "GND")
	)
	(segment
		(start 370.388134 -248.528078)
		(end 370.38788 -248.527824)
		(width 0.2032)
		(layer "F.Cu")
		(net "GND")
	)
	(segment
		(start 112.579912 -220.041978)
		(end 112.580166 -220.041724)
		(width 0.254)
		(layer "F.Cu")
		(net "GND")
	)
	(segment
		(start 162.913314 -264.466578)
		(end 161.808414 -264.466578)
		(width 0.381)
		(layer "F.Cu")
		(net "GND")
	)
	(segment
		(start 361.569762 -258.2672)
		(end 361.569762 -258.80314)
		(width 0.254)
		(layer "F.Cu")
		(net "GND")
	)
	(segment
		(start 65.047114 -261.066788)
		(end 66.152014 -261.066788)
		(width 0.381)
		(layer "F.Cu")
		(net "GND")
	)
	(segment
		(start 335.138268 -55.498746)
		(end 335.482692 -54.900068)
		(width 0.2032)
		(layer "F.Cu")
		(net "GND")
	)
	(segment
		(start 127.726694 -258.2672)
		(end 127.726694 -258.802886)
		(width 0.2032)
		(layer "F.Cu")
		(net "GND")
	)
	(segment
		(start 371.437916 -276.986492)
		(end 371.437662 -277.522432)
		(width 0.2032)
		(layer "F.Cu")
		(net "GND")
	)
	(segment
		(start 125.267466 -240.389156)
		(end 125.267466 -239.853216)
		(width 0.2032)
		(layer "F.Cu")
		(net "GND")
	)
	(segment
		(start 294.904414 -270.416782)
		(end 293.799514 -270.416782)
		(width 0.381)
		(layer "F.Cu")
		(net "GND")
	)
	(segment
		(start 386.004562 -281.05608)
		(end 386.004562 -281.59202)
		(width 0.13208)
		(layer "F.Cu")
		(net "GND")
	)
	(segment
		(start 20.995894 -114.199416)
		(end 21.458428 -114.199416)
		(width 0.3556)
		(layer "F.Cu")
		(net "GND")
	)
	(segment
		(start 294.899588 -365.651796)
		(end 295.3766 -365.174784)
		(width 0.2032)
		(layer "F.Cu")
		(net "GND")
	)
	(segment
		(start 452.016114 -210.916774)
		(end 453.121014 -210.916774)
		(width 0.381)
		(layer "F.Cu")
		(net "GND")
	)
	(segment
		(start 165.78072 -22.786848)
		(end 165.78072 -22.473158)
		(width 0.3556)
		(layer "F.Cu")
		(net "GND")
	)
	(segment
		(start 383.185162 -259.894832)
		(end 383.184908 -260.430518)
		(width 0.254)
		(layer "F.Cu")
		(net "GND")
	)
	(segment
		(start 463.659982 -264.466578)
		(end 464.764882 -264.466578)
		(width 0.381)
		(layer "F.Cu")
		(net "GND")
	)
	(segment
		(start 43.520614 -305.266598)
		(end 42.415714 -305.266598)
		(width 0.381)
		(layer "F.Cu")
		(net "GND")
	)
	(segment
		(start 333.845662 -285.661354)
		(end 333.845662 -285.125414)
		(width 0.254)
		(layer "F.Cu")
		(net "GND")
	)
	(segment
		(start 45.859446 -260.21665)
		(end 46.964346 -260.21665)
		(width 0.381)
		(layer "F.Cu")
		(net "GND")
	)
	(segment
		(start 447.467482 -194.766692)
		(end 448.572382 -194.766692)
		(width 0.381)
		(layer "F.Cu")
		(net "GND")
	)
	(segment
		(start 97.653094 -278.336248)
		(end 97.653348 -278.336502)
		(width 0.254)
		(layer "F.Cu")
		(net "GND")
	)
	(segment
		(start 130.076448 -283.497782)
		(end 130.076448 -284.033468)
		(width 0.254)
		(layer "F.Cu")
		(net "GND")
	)
	(segment
		(start 457.221082 -295.916604)
		(end 456.116182 -295.916604)
		(width 0.381)
		(layer "F.Cu")
		(net "GND")
	)
	(segment
		(start 457.221082 -316.316614)
		(end 456.116182 -316.316614)
		(width 0.381)
		(layer "F.Cu")
		(net "GND")
	)
	(segment
		(start 53.403246 -240.666778)
		(end 54.508146 -240.666778)
		(width 0.381)
		(layer "F.Cu")
		(net "GND")
	)
	(segment
		(start 424.836082 -244.066568)
		(end 425.940982 -244.066568)
		(width 0.381)
		(layer "F.Cu")
		(net "GND")
	)
	(segment
		(start 457.221082 -280.61666)
		(end 456.116182 -280.61666)
		(width 0.381)
		(layer "F.Cu")
		(net "GND")
	)
	(segment
		(start 307.782214 -260.21665)
		(end 308.887114 -260.21665)
		(width 0.381)
		(layer "F.Cu")
		(net "GND")
	)
	(segment
		(start 129.496312 -231.436418)
		(end 129.496566 -231.436164)
		(width 0.2032)
		(layer "F.Cu")
		(net "GND")
	)
	(segment
		(start 285.150814 -233.016806)
		(end 286.255714 -233.016806)
		(width 0.381)
		(layer "F.Cu")
		(net "GND")
	)
	(segment
		(start 328.244962 -52.952396)
		(end 329.437492 -53.148738)
		(width 0.2032)
		(layer "F.Cu")
		(net "GND")
	)
	(segment
		(start 59.842146 -292.516814)
		(end 60.947046 -292.516814)
		(width 0.381)
		(layer "F.Cu")
		(net "GND")
	)
	(segment
		(start 297.899582 -266.1666)
		(end 299.004482 -266.1666)
		(width 0.381)
		(layer "F.Cu")
		(net "GND")
	)
	(segment
		(start 420.26967 -132.21716)
		(end 419.58006 -132.21716)
		(width 0.3556)
		(layer "F.Cu")
		(net "GND")
	)
	(segment
		(start 308.887114 -300.166786)
		(end 309.992014 -300.166786)
		(width 0.381)
		(layer "F.Cu")
		(net "GND")
	)
	(segment
		(start 126.676912 -222.76181)
		(end 126.677166 -222.761556)
		(width 0.254)
		(layer "F.Cu")
		(net "GND")
	)
	(segment
		(start 347.847666 -52.929536)
		(end 347.641926 -52.929536)
		(width 0.2032)
		(layer "F.Cu")
		(net "GND")
	)
	(segment
		(start 267.724382 -295.916604)
		(end 268.829282 -295.916604)
		(width 0.381)
		(layer "F.Cu")
		(net "GND")
	)
	(segment
		(start 14.426946 -387.119876)
		(end 15.036546 -387.119876)
		(width 0.3556)
		(layer "F.Cu")
		(net "GND")
	)
	(segment
		(start 341.902034 -39.295324)
		(end 342.90254 -39.295324)
		(width 0.2032)
		(layer "F.Cu")
		(net "GND")
	)
	(segment
		(start 366.738916 -275.35886)
		(end 366.738916 -275.8948)
		(width 0.254)
		(layer "F.Cu")
		(net "GND")
	)
	(segment
		(start 428.279814 -272.116804)
		(end 429.384714 -272.116804)
		(width 0.381)
		(layer "F.Cu")
		(net "GND")
	)
	(segment
		(start 196.532246 -283.166566)
		(end 195.427346 -283.166566)
		(width 0.381)
		(layer "F.Cu")
		(net "GND")
	)
	(segment
		(start 165.252146 -290.816792)
		(end 166.357046 -290.816792)
		(width 0.381)
		(layer "F.Cu")
		(net "GND")
	)
	(segment
		(start 103.762048 -264.500106)
		(end 103.761794 -264.50036)
		(width 0.254)
		(layer "F.Cu")
		(net "GND")
	)
	(segment
		(start 343.550494 -54.088792)
		(end 343.822274 -54.558692)
		(width 0.2032)
		(layer "F.Cu")
		(net "GND")
	)
	(segment
		(start 274.31365 -95.029274)
		(end 273.62658 -95.029274)
		(width 0.3556)
		(layer "F.Cu")
		(net "GND")
	)
	(segment
		(start 117.859048 -275.35886)
		(end 117.858794 -275.8948)
		(width 0.254)
		(layer "F.Cu")
		(net "GND")
	)
	(segment
		(start 384.124962 -263.686544)
		(end 384.124962 -263.150604)
		(width 0.254)
		(layer "F.Cu")
		(net "GND")
	)
	(segment
		(start 116.449094 -287.567116)
		(end 116.449094 -288.102802)
		(width 0.254)
		(layer "F.Cu")
		(net "GND")
	)
	(segment
		(start 18.646902 -393.45362)
		(end 18.95729 -393.45362)
		(width 0.254)
		(layer "F.Cu")
		(net "GND")
	)
	(segment
		(start 18.679414 -271.266666)
		(end 19.784314 -271.266666)
		(width 0.381)
		(layer "F.Cu")
		(net "GND")
	)
	(segment
		(start 413.192214 -261.916672)
		(end 414.297114 -261.916672)
		(width 0.381)
		(layer "F.Cu")
		(net "GND")
	)
	(segment
		(start 364.88878 -390.390888)
		(end 364.88878 -390.749028)
		(width 0.3556)
		(layer "F.Cu")
		(net "GND")
	)
	(segment
		(start 435.823614 -227.066602)
		(end 436.928514 -227.066602)
		(width 0.381)
		(layer "F.Cu")
		(net "GND")
	)
	(segment
		(start 456.343258 -382.536446)
		(end 455.986642 -382.17983)
		(width 0.1778)
		(layer "F.Cu")
		(net "GND")
	)
	(segment
		(start 124.327666 -242.017042)
		(end 124.327412 -242.016788)
		(width 0.2032)
		(layer "F.Cu")
		(net "GND")
	)
	(segment
		(start 432.379882 -314.616592)
		(end 433.484782 -314.616592)
		(width 0.381)
		(layer "F.Cu")
		(net "GND")
	)
	(segment
		(start 272.273014 -304.416714)
		(end 271.168114 -304.416714)
		(width 0.381)
		(layer "F.Cu")
		(net "GND")
	)
	(segment
		(start 370.85778 -231.436418)
		(end 370.858034 -231.436164)
		(width 0.254)
		(layer "F.Cu")
		(net "GND")
	)
	(segment
		(start 87.675466 -224.111566)
		(end 87.675466 -223.575626)
		(width 0.254)
		(layer "F.Cu")
		(net "GND")
	)
	(segment
		(start 23.946866 -11.26998)
		(end 23.946866 -12.37488)
		(width 0.3556)
		(layer "F.Cu")
		(net "GND")
	)
	(segment
		(start 444.472314 -285.716726)
		(end 445.577214 -285.716726)
		(width 0.381)
		(layer "F.Cu")
		(net "GND")
	)
	(segment
		(start 118.798848 -272.103342)
		(end 118.798594 -272.639282)
		(width 0.2032)
		(layer "F.Cu")
		(net "GND")
	)
	(segment
		(start 8.140446 -210.916774)
		(end 9.245346 -210.916774)
		(width 0.381)
		(layer "F.Cu")
		(net "GND")
	)
	(segment
		(start 419.502082 -316.316614)
		(end 418.397182 -316.316614)
		(width 0.381)
		(layer "F.Cu")
		(net "GND")
	)
	(segment
		(start 133.365494 -255.011682)
		(end 133.365494 -255.547622)
		(width 0.2032)
		(layer "F.Cu")
		(net "GND")
	)
	(segment
		(start 168.883584 -355.81463)
		(end 168.883584 -355.996494)
		(width 0.2032)
		(layer "F.Cu")
		(net "GND")
	)
	(segment
		(start 371.327934 -245.27256)
		(end 371.32768 -245.272306)
		(width 0.2032)
		(layer "F.Cu")
		(net "GND")
	)
	(segment
		(start 208.176114 -291.666676)
		(end 209.281014 -291.666676)
		(width 0.381)
		(layer "F.Cu")
		(net "GND")
	)
	(segment
		(start 426.54982 -344.017346)
		(end 427.490128 -344.017346)
		(width 0.508)
		(layer "F.Cu")
		(net "GND")
	)
	(segment
		(start 439.923682 -275.516594)
		(end 441.028582 -275.516594)
		(width 0.381)
		(layer "F.Cu")
		(net "GND")
	)
	(segment
		(start 210.514946 -238.966756)
		(end 211.619846 -238.966756)
		(width 0.381)
		(layer "F.Cu")
		(net "GND")
	)
	(segment
		(start 262.519414 -290.816792)
		(end 263.624314 -290.816792)
		(width 0.381)
		(layer "F.Cu")
		(net "GND")
	)
	(segment
		(start 23.228046 -208.366614)
		(end 24.332946 -208.366614)
		(width 0.381)
		(layer "F.Cu")
		(net "GND")
	)
	(segment
		(start 462.555082 -239.81664)
		(end 463.659982 -239.81664)
		(width 0.381)
		(layer "F.Cu")
		(net "GND")
	)
	(segment
		(start 207.071214 -213.46668)
		(end 208.176114 -213.46668)
		(width 0.381)
		(layer "F.Cu")
		(net "GND")
	)
	(segment
		(start 92.954094 -277.800562)
		(end 92.954094 -278.336248)
		(width 0.2032)
		(layer "F.Cu")
		(net "GND")
	)
	(segment
		(start 179.755546 -115.375436)
		(end 180.155596 -115.775486)
		(width 0.3556)
		(layer "F.Cu")
		(net "GND")
	)
	(segment
		(start 117.859048 -265.592306)
		(end 117.859048 -266.127992)
		(width 0.254)
		(layer "F.Cu")
		(net "GND")
	)
	(segment
		(start 12.240514 -282.316682)
		(end 13.345414 -282.316682)
		(width 0.381)
		(layer "F.Cu")
		(net "GND")
	)
	(segment
		(start 312.987182 -301.01667)
		(end 314.092082 -301.01667)
		(width 0.381)
		(layer "F.Cu")
		(net "GND")
	)
	(segment
		(start 333.400146 -54.747668)
		(end 333.23657 -55.028846)
		(width 0.2032)
		(layer "F.Cu")
		(net "GND")
	)
	(segment
		(start 30.771846 -229.616762)
		(end 31.876746 -229.616762)
		(width 0.381)
		(layer "F.Cu")
		(net "GND")
	)
	(segment
		(start 429.384714 -278.066754)
		(end 430.489614 -278.066754)
		(width 0.381)
		(layer "F.Cu")
		(net "GND")
	)
	(segment
		(start 305.443382 -278.916638)
		(end 306.548282 -278.916638)
		(width 0.381)
		(layer "F.Cu")
		(net "GND")
	)
	(segment
		(start 365.219234 -234.691936)
		(end 365.219234 -234.15625)
		(width 0.2032)
		(layer "F.Cu")
		(net "GND")
	)
	(segment
		(start 347.472762 -258.2672)
		(end 347.472762 -258.802886)
		(width 0.2032)
		(layer "F.Cu")
		(net "GND")
	)
	(segment
		(start 330.252578 -45.160946)
		(end 329.980798 -44.691046)
		(width 0.254)
		(layer "F.Cu")
		(net "GND")
	)
	(segment
		(start 345.593162 -257.175254)
		(end 345.593162 -256.639314)
		(width 0.2032)
		(layer "F.Cu")
		(net "GND")
	)
	(segment
		(start 340.894162 -268.033754)
		(end 340.894416 -268.034008)
		(width 0.2032)
		(layer "F.Cu")
		(net "GND")
	)
	(segment
		(start 352.641662 -268.847824)
		(end 352.641662 -269.38351)
		(width 0.254)
		(layer "F.Cu")
		(net "GND")
	)
	(segment
		(start 170.457114 -303.566576)
		(end 169.352214 -303.566576)
		(width 0.381)
		(layer "F.Cu")
		(net "GND")
	)
	(segment
		(start 367.678716 -266.127992)
		(end 367.678462 -266.128246)
		(width 0.2032)
		(layer "F.Cu")
		(net "GND")
	)
	(segment
		(start 424.836082 -205.816708)
		(end 425.940982 -205.816708)
		(width 0.381)
		(layer "F.Cu")
		(net "GND")
	)
	(segment
		(start 27.328114 -267.866622)
		(end 28.433014 -267.866622)
		(width 0.381)
		(layer "F.Cu")
		(net "GND")
	)
	(segment
		(start 105.061512 -220.041978)
		(end 105.061766 -220.041724)
		(width 0.254)
		(layer "F.Cu")
		(net "GND")
	)
	(segment
		(start 424.836082 -233.86669)
		(end 425.940982 -233.86669)
		(width 0.381)
		(layer "F.Cu")
		(net "GND")
	)
	(segment
		(start 166.357046 -229.616762)
		(end 165.252146 -229.616762)
		(width 0.381)
		(layer "F.Cu")
		(net "GND")
	)
	(segment
		(start 344.183716 -284.033468)
		(end 344.183462 -284.033722)
		(width 0.254)
		(layer "F.Cu")
		(net "GND")
	)
	(segment
		(start 371.907562 -255.547368)
		(end 371.907816 -255.547622)
		(width 0.2032)
		(layer "F.Cu")
		(net "GND")
	)
	(segment
		(start 294.904414 -240.666778)
		(end 293.799514 -240.666778)
		(width 0.381)
		(layer "F.Cu")
		(net "GND")
	)
	(segment
		(start 122.917712 -226.017582)
		(end 122.917966 -226.017328)
		(width 0.254)
		(layer "F.Cu")
		(net "GND")
	)
	(segment
		(start 207.071214 -316.316614)
		(end 208.176114 -316.316614)
		(width 0.381)
		(layer "F.Cu")
		(net "GND")
	)
	(segment
		(start 39.420546 -234.716574)
		(end 38.315646 -234.716574)
		(width 0.381)
		(layer "F.Cu")
		(net "GND")
	)
	(segment
		(start 53.403246 -307.816758)
		(end 54.508146 -307.816758)
		(width 0.381)
		(layer "F.Cu")
		(net "GND")
	)
	(segment
		(start 53.403246 -309.51678)
		(end 54.508146 -309.51678)
		(width 0.381)
		(layer "F.Cu")
		(net "GND")
	)
	(segment
		(start 277.607014 -278.066754)
		(end 278.711914 -278.066754)
		(width 0.381)
		(layer "F.Cu")
		(net "GND")
	)
	(segment
		(start 274.163282 -241.516662)
		(end 275.268182 -241.516662)
		(width 0.381)
		(layer "F.Cu")
		(net "GND")
	)
	(segment
		(start 254.975614 -223.666558)
		(end 256.080514 -223.666558)
		(width 0.381)
		(layer "F.Cu")
		(net "GND")
	)
	(segment
		(start 289.250882 -288.266632)
		(end 290.355782 -288.266632)
		(width 0.381)
		(layer "F.Cu")
		(net "GND")
	)
	(segment
		(start 170.457114 -244.066568)
		(end 171.562014 -244.066568)
		(width 0.381)
		(layer "F.Cu")
		(net "GND")
	)
	(segment
		(start 182.549546 -296.766742)
		(end 181.444646 -296.766742)
		(width 0.381)
		(layer "F.Cu")
		(net "GND")
	)
	(segment
		(start 26.915618 -109.658658)
		(end 25.734518 -109.658658)
		(width 0.3556)
		(layer "F.Cu")
		(net "GND")
	)
	(segment
		(start 92.954094 -264.778236)
		(end 92.954094 -265.313922)
		(width 0.2032)
		(layer "F.Cu")
		(net "GND")
	)
	(segment
		(start 362.979716 -276.986492)
		(end 362.979716 -277.522178)
		(width 0.254)
		(layer "F.Cu")
		(net "GND")
	)
	(segment
		(start 429.384714 -301.866808)
		(end 430.489614 -301.866808)
		(width 0.381)
		(layer "F.Cu")
		(net "GND")
	)
	(segment
		(start 175.005746 -204.96657)
		(end 173.900846 -204.96657)
		(width 0.381)
		(layer "F.Cu")
		(net "GND")
	)
	(segment
		(start 267.724382 -211.766658)
		(end 268.829282 -211.766658)
		(width 0.381)
		(layer "F.Cu")
		(net "GND")
	)
	(segment
		(start 132.785866 -224.111566)
		(end 132.785866 -223.575626)
		(width 0.2032)
		(layer "F.Cu")
		(net "GND")
	)
	(segment
		(start 456.116182 -198.166736)
		(end 455.011282 -198.166736)
		(width 0.381)
		(layer "F.Cu")
		(net "GND")
	)
	(segment
		(start 334.899508 -48.050196)
		(end 335.299558 -48.450246)
		(width 0.2032)
		(layer "F.Cu")
		(net "GND")
	)
	(segment
		(start 207.071214 -210.066636)
		(end 208.176114 -210.066636)
		(width 0.381)
		(layer "F.Cu")
		(net "GND")
	)
	(segment
		(start 92.844112 -233.064304)
		(end 92.844366 -233.06405)
		(width 0.254)
		(layer "F.Cu")
		(net "GND")
	)
	(segment
		(start 123.387612 -245.272306)
		(end 123.387612 -244.73662)
		(width 0.2032)
		(layer "F.Cu")
		(net "GND")
	)
	(segment
		(start 110.230666 -243.109496)
		(end 110.23092 -243.109242)
		(width 0.254)
		(layer "F.Cu")
		(net "GND")
	)
	(segment
		(start 278.711914 -258.516628)
		(end 279.816814 -258.516628)
		(width 0.381)
		(layer "F.Cu")
		(net "GND")
	)
	(segment
		(start 20.816062 -165.039548)
		(end 20.51431 -164.737796)
		(width 0.3556)
		(layer "F.Cu")
		(net "GND")
	)
	(segment
		(start 85.435694 -264.778236)
		(end 85.905594 -264.50036)
		(width 0.254)
		(layer "F.Cu")
		(net "GND")
	)
	(segment
		(start 406.753314 -300.166786)
		(end 407.858214 -300.166786)
		(width 0.381)
		(layer "F.Cu")
		(net "GND")
	)
	(segment
		(start 178.000914 -198.166736)
		(end 176.896014 -198.166736)
		(width 0.381)
		(layer "F.Cu")
		(net "GND")
	)
	(segment
		(start 53.403246 -246.616728)
		(end 54.508146 -246.616728)
		(width 0.381)
		(layer "F.Cu")
		(net "GND")
	)
	(segment
		(start 12.240514 -262.76681)
		(end 13.345414 -262.76681)
		(width 0.381)
		(layer "F.Cu")
		(net "GND")
	)
	(segment
		(start 261.285482 -295.916604)
		(end 260.180582 -295.916604)
		(width 0.381)
		(layer "F.Cu")
		(net "GND")
	)
	(segment
		(start 123.027694 -282.683966)
		(end 123.027948 -282.68422)
		(width 0.254)
		(layer "F.Cu")
		(net "GND")
	)
	(segment
		(start 262.519414 -216.016586)
		(end 263.624314 -216.016586)
		(width 0.381)
		(layer "F.Cu")
		(net "GND")
	)
	(segment
		(start 334.05064 -54.558946)
		(end 333.510128 -54.558946)
		(width 0.2032)
		(layer "F.Cu")
		(net "GND")
	)
	(segment
		(start 452.016114 -278.066754)
		(end 450.911214 -278.066754)
		(width 0.381)
		(layer "F.Cu")
		(net "GND")
	)
	(segment
		(start 271.168114 -287.416748)
		(end 270.063214 -287.416748)
		(width 0.381)
		(layer "F.Cu")
		(net "GND")
	)
	(segment
		(start 378.846334 -228.99497)
		(end 378.84608 -228.994716)
		(width 0.2032)
		(layer "F.Cu")
		(net "GND")
	)
	(segment
		(start 381.305562 -255.011682)
		(end 381.305562 -255.547622)
		(width 0.2032)
		(layer "F.Cu")
		(net "GND")
	)
	(segment
		(start 352.06178 -226.553268)
		(end 352.06178 -226.017582)
		(width 0.254)
		(layer "F.Cu")
		(net "GND")
	)
	(segment
		(start 14.579346 -197.316598)
		(end 15.684246 -197.316598)
		(width 0.381)
		(layer "F.Cu")
		(net "GND")
	)
	(segment
		(start 33.767014 -226.216718)
		(end 34.871914 -226.216718)
		(width 0.381)
		(layer "F.Cu")
		(net "GND")
	)
	(segment
		(start 92.844366 -220.041724)
		(end 92.844366 -219.506038)
		(width 0.254)
		(layer "F.Cu")
		(net "GND")
	)
	(segment
		(start 374.257316 -266.127992)
		(end 374.257062 -266.128246)
		(width 0.254)
		(layer "F.Cu")
		(net "GND")
	)
	(segment
		(start 382.245362 -257.175254)
		(end 382.245362 -256.639314)
		(width 0.2032)
		(layer "F.Cu")
		(net "GND")
	)
	(segment
		(start 204.076046 -246.616728)
		(end 205.180946 -246.616728)
		(width 0.381)
		(layer "F.Cu")
		(net "GND")
	)
	(segment
		(start 185.544714 -272.966688)
		(end 184.439814 -272.966688)
		(width 0.381)
		(layer "F.Cu")
		(net "GND")
	)
	(segment
		(start 374.61698 -233.064304)
		(end 374.61698 -232.528364)
		(width 0.2032)
		(layer "F.Cu")
		(net "GND")
	)
	(segment
		(start 156.25699 -17.655032)
		(end 156.25699 -16.550132)
		(width 0.3556)
		(layer "F.Cu")
		(net "GND")
	)
	(segment
		(start 173.900846 -268.71676)
		(end 172.795946 -268.71676)
		(width 0.381)
		(layer "F.Cu")
		(net "GND")
	)
	(segment
		(start 410.853382 -267.866622)
		(end 411.958282 -267.866622)
		(width 0.381)
		(layer "F.Cu")
		(net "GND")
	)
	(segment
		(start 380.25578 -249.342148)
		(end 380.256034 -249.341894)
		(width 0.2032)
		(layer "F.Cu")
		(net "GND")
	)
	(segment
		(start 129.966212 -250.15571)
		(end 129.966212 -249.620024)
		(width 0.2032)
		(layer "F.Cu")
		(net "GND")
	)
	(segment
		(start 343.133934 -240.389156)
		(end 343.13368 -240.388902)
		(width 0.2032)
		(layer "F.Cu")
		(net "GND")
	)
	(segment
		(start 312.987182 -228.766624)
		(end 311.666382 -228.766624)
		(width 0.381)
		(layer "F.Cu")
		(net "GND")
	)
	(segment
		(start 254.975614 -204.96657)
		(end 256.080514 -204.96657)
		(width 0.381)
		(layer "F.Cu")
		(net "GND")
	)
	(segment
		(start 404.341076 -64.040004)
		(end 404.341076 -62.999112)
		(width 0.3556)
		(layer "F.Cu")
		(net "GND")
	)
	(segment
		(start 178.9557 -112.175544)
		(end 179.35575 -111.775494)
		(width 0.3556)
		(layer "F.Cu")
		(net "GND")
	)
	(segment
		(start 344.183716 -272.639028)
		(end 344.183462 -272.639282)
		(width 0.2032)
		(layer "F.Cu")
		(net "GND")
	)
	(segment
		(start 197.637146 -315.46673)
		(end 196.532246 -315.46673)
		(width 0.381)
		(layer "F.Cu")
		(net "GND")
	)
	(segment
		(start 214.615014 -204.116686)
		(end 215.719914 -204.116686)
		(width 0.381)
		(layer "F.Cu")
		(net "GND")
	)
	(segment
		(start 113.519712 -247.179084)
		(end 113.52022 -247.178576)
		(width 0.254)
		(layer "F.Cu")
		(net "GND")
	)
	(segment
		(start 7.035546 -296.766742)
		(end 8.140446 -296.766742)
		(width 0.381)
		(layer "F.Cu")
		(net "GND")
	)
	(segment
		(start 340.894416 -269.661894)
		(end 340.894416 -270.19758)
		(width 0.2032)
		(layer "F.Cu")
		(net "GND")
	)
	(segment
		(start 296.794682 -215.166702)
		(end 297.899582 -215.166702)
		(width 0.381)
		(layer "F.Cu")
		(net "GND")
	)
	(segment
		(start 54.508146 -206.666592)
		(end 53.403246 -206.666592)
		(width 0.381)
		(layer "F.Cu")
		(net "GND")
	)
	(segment
		(start 121.762266 -114.92103)
		(end 122.019822 -115.178586)
		(width 0.3556)
		(layer "F.Cu")
		(net "GND")
	)
	(segment
		(start 457.221082 -294.216582)
		(end 456.116182 -294.216582)
		(width 0.381)
		(layer "F.Cu")
		(net "GND")
	)
	(segment
		(start 56.398414 -230.466646)
		(end 57.503314 -230.466646)
		(width 0.381)
		(layer "F.Cu")
		(net "GND")
	)
	(segment
		(start 369.91798 -216.250774)
		(end 369.918234 -216.25052)
		(width 0.254)
		(layer "F.Cu")
		(net "GND")
	)
	(segment
		(start 379.896116 -262.336534)
		(end 379.896116 -262.872474)
		(width 0.2032)
		(layer "F.Cu")
		(net "GND")
	)
	(segment
		(start 42.415714 -194.766692)
		(end 41.310814 -194.766692)
		(width 0.381)
		(layer "F.Cu")
		(net "GND")
	)
	(segment
		(start 356.76078 -229.808786)
		(end 356.761034 -229.808532)
		(width 0.2032)
		(layer "F.Cu")
		(net "GND")
	)
	(segment
		(start 122.558048 -281.869896)
		(end 122.557794 -282.405836)
		(width 0.254)
		(layer "F.Cu")
		(net "GND")
	)
	(segment
		(start 11.135614 -210.066636)
		(end 12.240514 -210.066636)
		(width 0.381)
		(layer "F.Cu")
		(net "GND")
	)
	(segment
		(start 45.859446 -204.96657)
		(end 46.964346 -204.96657)
		(width 0.381)
		(layer "F.Cu")
		(net "GND")
	)
	(segment
		(start 435.823614 -281.466798)
		(end 436.928514 -281.466798)
		(width 0.381)
		(layer "F.Cu")
		(net "GND")
	)
	(segment
		(start 456.116182 -305.266598)
		(end 455.011282 -305.266598)
		(width 0.381)
		(layer "F.Cu")
		(net "GND")
	)
	(segment
		(start 203.1492 -94.56801)
		(end 203.1492 -93.6498)
		(width 0.3556)
		(layer "F.Cu")
		(net "GND")
	)
	(segment
		(start 105.641648 -268.84757)
		(end 105.641394 -268.847824)
		(width 0.254)
		(layer "F.Cu")
		(net "GND")
	)
	(segment
		(start 376.026934 -245.27256)
		(end 376.02668 -245.272306)
		(width 0.2032)
		(layer "F.Cu")
		(net "GND")
	)
	(segment
		(start 373.787162 -277.800562)
		(end 373.787416 -278.336502)
		(width 0.2032)
		(layer "F.Cu")
		(net "GND")
	)
	(segment
		(start 157.708346 -195.616576)
		(end 158.813246 -195.616576)
		(width 0.381)
		(layer "F.Cu")
		(net "GND")
	)
	(segment
		(start 373.677434 -220.041724)
		(end 373.677434 -219.506038)
		(width 0.254)
		(layer "F.Cu")
		(net "GND")
	)
	(segment
		(start 161.808414 -239.81664)
		(end 162.913314 -239.81664)
		(width 0.381)
		(layer "F.Cu")
		(net "GND")
	)
	(segment
		(start 282.811982 -249.166634)
		(end 283.916882 -249.166634)
		(width 0.381)
		(layer "F.Cu")
		(net "GND")
	)
	(segment
		(start 43.520614 -271.266666)
		(end 42.415714 -271.266666)
		(width 0.381)
		(layer "F.Cu")
		(net "GND")
	)
	(segment
		(start 435.823614 -220.266768)
		(end 436.928514 -220.266768)
		(width 0.381)
		(layer "F.Cu")
		(net "GND")
	)
	(segment
		(start 175.005746 -203.266802)
		(end 173.900846 -203.266802)
		(width 0.381)
		(layer "F.Cu")
		(net "GND")
	)
	(segment
		(start 49.959514 -204.116686)
		(end 51.064414 -204.116686)
		(width 0.381)
		(layer "F.Cu")
		(net "GND")
	)
	(segment
		(start 59.842146 -298.466764)
		(end 60.947046 -298.466764)
		(width 0.381)
		(layer "F.Cu")
		(net "GND")
	)
	(segment
		(start 126.786894 -289.195002)
		(end 126.786894 -289.807142)
		(width 0.2032)
		(layer "F.Cu")
		(net "GND")
	)
	(segment
		(start 14.579346 -238.966756)
		(end 15.684246 -238.966756)
		(width 0.381)
		(layer "F.Cu")
		(net "GND")
	)
	(segment
		(start 347.284294 -57.024016)
		(end 347.214698 -56.95442)
		(width 0.2032)
		(layer "F.Cu")
		(net "GND")
	)
	(segment
		(start 211.619846 -210.916774)
		(end 212.724746 -210.916774)
		(width 0.381)
		(layer "F.Cu")
		(net "GND")
	)
	(segment
		(start 77.47635 -37.262308)
		(end 77.47635 -36.627308)
		(width 0.3556)
		(layer "F.Cu")
		(net "GND")
	)
	(segment
		(start 339.374734 -238.225584)
		(end 339.374734 -238.761524)
		(width 0.2032)
		(layer "F.Cu")
		(net "GND")
	)
	(segment
		(start 344.183716 -272.103342)
		(end 344.183716 -272.639028)
		(width 0.2032)
		(layer "F.Cu")
		(net "GND")
	)
	(segment
		(start 429.129952 -395.798548)
		(end 429.764952 -395.798548)
		(width 0.3556)
		(layer "F.Cu")
		(net "GND")
	)
	(segment
		(start 314.092082 -228.766624)
		(end 312.987182 -228.766624)
		(width 0.381)
		(layer "F.Cu")
		(net "GND")
	)
	(segment
		(start 204.076046 -220.266768)
		(end 205.180946 -220.266768)
		(width 0.381)
		(layer "F.Cu")
		(net "GND")
	)
	(segment
		(start 370.027962 -282.683966)
		(end 370.027962 -283.219906)
		(width 0.254)
		(layer "F.Cu")
		(net "GND")
	)
	(segment
		(start 385.065016 -265.314176)
		(end 385.534662 -265.592306)
		(width 0.254)
		(layer "F.Cu")
		(net "GND")
	)
	(segment
		(start 449.677282 -213.46668)
		(end 448.572382 -213.46668)
		(width 0.381)
		(layer "F.Cu")
		(net "GND")
	)
	(segment
		(start 30.771846 -251.716794)
		(end 31.876746 -251.716794)
		(width 0.381)
		(layer "F.Cu")
		(net "GND")
	)
	(segment
		(start 348.30258 -216.250774)
		(end 348.302834 -216.25052)
		(width 0.254)
		(layer "F.Cu")
		(net "GND")
	)
	(segment
		(start 196.532246 -231.316784)
		(end 197.637146 -231.316784)
		(width 0.381)
		(layer "F.Cu")
		(net "GND")
	)
	(segment
		(start 130.906266 -238.761524)
		(end 130.906012 -238.76127)
		(width 0.2032)
		(layer "F.Cu")
		(net "GND")
	)
	(segment
		(start 374.147334 -242.017042)
		(end 374.14708 -242.016788)
		(width 0.2032)
		(layer "F.Cu")
		(net "GND")
	)
	(segment
		(start 99.532694 -255.547368)
		(end 99.532948 -255.547622)
		(width 0.2032)
		(layer "F.Cu")
		(net "GND")
	)
	(segment
		(start 188.988446 -244.916706)
		(end 187.883546 -244.916706)
		(width 0.381)
		(layer "F.Cu")
		(net "GND")
	)
	(segment
		(start 267.724382 -306.96662)
		(end 268.829282 -306.96662)
		(width 0.381)
		(layer "F.Cu")
		(net "GND")
	)
	(segment
		(start 180.339746 -260.21665)
		(end 181.444646 -260.21665)
		(width 0.381)
		(layer "F.Cu")
		(net "GND")
	)
	(segment
		(start 429.384714 -208.366614)
		(end 430.489614 -208.366614)
		(width 0.381)
		(layer "F.Cu")
		(net "GND")
	)
	(segment
		(start 167.461946 -227.066602)
		(end 166.357046 -227.066602)
		(width 0.381)
		(layer "F.Cu")
		(net "GND")
	)
	(segment
		(start 378.37618 -216.78646)
		(end 378.37618 -216.250774)
		(width 0.254)
		(layer "F.Cu")
		(net "GND")
	)
	(segment
		(start 173.900846 -267.016738)
		(end 175.005746 -267.016738)
		(width 0.381)
		(layer "F.Cu")
		(net "GND")
	)
	(segment
		(start 254.975614 -258.516628)
		(end 256.080514 -258.516628)
		(width 0.381)
		(layer "F.Cu")
		(net "GND")
	)
	(segment
		(start 121.618248 -286.7533)
		(end 121.618248 -287.288986)
		(width 0.254)
		(layer "F.Cu")
		(net "GND")
	)
	(segment
		(start 289.250882 -305.266598)
		(end 290.355782 -305.266598)
		(width 0.381)
		(layer "F.Cu")
		(net "GND")
	)
	(segment
		(start 26.223214 -228.766624)
		(end 27.328114 -228.766624)
		(width 0.381)
		(layer "F.Cu")
		(net "GND")
	)
	(segment
		(start 370.967762 -281.05608)
		(end 370.967762 -281.591512)
		(width 0.254)
		(layer "F.Cu")
		(net "GND")
	)
	(segment
		(start 73.106026 -174.903638)
		(end 73.106026 -175.538638)
		(width 0.3556)
		(layer "F.Cu")
		(net "GND")
	)
	(segment
		(start 18.679414 -288.266632)
		(end 19.784314 -288.266632)
		(width 0.381)
		(layer "F.Cu")
		(net "GND")
	)
	(segment
		(start 107.990894 -273.452844)
		(end 107.991148 -273.453098)
		(width 0.2032)
		(layer "F.Cu")
		(net "GND")
	)
	(segment
		(start 362.546646 -365.687864)
		(end 362.546646 -366.465104)
		(width 0.381)
		(layer "F.Cu")
		(net "GND")
	)
	(segment
		(start 435.823614 -204.96657)
		(end 436.928514 -204.96657)
		(width 0.381)
		(layer "F.Cu")
		(net "GND")
	)
	(segment
		(start 197.637146 -214.316564)
		(end 196.532246 -214.316564)
		(width 0.381)
		(layer "F.Cu")
		(net "GND")
	)
	(segment
		(start 352.06178 -229.808786)
		(end 352.062034 -229.808532)
		(width 0.2032)
		(layer "F.Cu")
		(net "GND")
	)
	(segment
		(start 468.164164 -62.05982)
		(end 468.164164 -61.447934)
		(width 0.3556)
		(layer "F.Cu")
		(net "GND")
	)
	(segment
		(start 342.66378 -220.041978)
		(end 342.664034 -220.041724)
		(width 0.254)
		(layer "F.Cu")
		(net "GND")
	)
	(segment
		(start 260.180582 -267.866622)
		(end 259.075682 -267.866622)
		(width 0.381)
		(layer "F.Cu")
		(net "GND")
	)
	(segment
		(start 305.443382 -247.466612)
		(end 306.548282 -247.466612)
		(width 0.381)
		(layer "F.Cu")
		(net "GND")
	)
	(segment
		(start 172.795946 -296.766742)
		(end 173.900846 -296.766742)
		(width 0.381)
		(layer "F.Cu")
		(net "GND")
	)
	(segment
		(start 375.55678 -231.436418)
		(end 375.557034 -231.436164)
		(width 0.2032)
		(layer "F.Cu")
		(net "GND")
	)
	(segment
		(start 199.527414 -228.766624)
		(end 200.632314 -228.766624)
		(width 0.381)
		(layer "F.Cu")
		(net "GND")
	)
	(segment
		(start 330.252578 -50.799746)
		(end 329.980798 -50.329846)
		(width 0.2032)
		(layer "F.Cu")
		(net "GND")
	)
	(segment
		(start 339.374734 -223.575626)
		(end 339.374734 -224.111566)
		(width 0.2032)
		(layer "F.Cu")
		(net "GND")
	)
	(segment
		(start 300.238414 -206.666592)
		(end 301.343314 -206.666592)
		(width 0.381)
		(layer "F.Cu")
		(net "GND")
	)
	(segment
		(start 372.847362 -279.428194)
		(end 372.847616 -279.964134)
		(width 0.254)
		(layer "F.Cu")
		(net "GND")
	)
	(segment
		(start 30.771846 -265.316716)
		(end 31.876746 -265.316716)
		(width 0.381)
		(layer "F.Cu")
		(net "GND")
	)
	(segment
		(start 277.607014 -268.71676)
		(end 278.711914 -268.71676)
		(width 0.381)
		(layer "F.Cu")
		(net "GND")
	)
	(segment
		(start 105.061512 -226.553268)
		(end 105.061512 -226.017582)
		(width 0.254)
		(layer "F.Cu")
		(net "GND")
	)
	(segment
		(start 121.038112 -222.76181)
		(end 121.038366 -222.761556)
		(width 0.254)
		(layer "F.Cu")
		(net "GND")
	)
	(segment
		(start 119.268494 -279.428194)
		(end 119.268748 -279.964134)
		(width 0.254)
		(layer "F.Cu")
		(net "GND")
	)
	(segment
		(start 124.00915 -413.361378)
		(end 124.00915 -414.283652)
		(width 0.508)
		(layer "F.Cu")
		(net "GND")
	)
	(segment
		(start 278.711914 -279.766776)
		(end 279.816814 -279.766776)
		(width 0.381)
		(layer "F.Cu")
		(net "GND")
	)
	(segment
		(start 178.000914 -219.41663)
		(end 176.896014 -219.41663)
		(width 0.381)
		(layer "F.Cu")
		(net "GND")
	)
	(segment
		(start 341.402162 -39.443152)
		(end 340.901782 -39.295324)
		(width 0.2032)
		(layer "F.Cu")
		(net "GND")
	)
	(segment
		(start 341.37727 -54.089046)
		(end 341.37727 -53.149246)
		(width 0.2032)
		(layer "F.Cu")
		(net "GND")
	)
	(segment
		(start 365.689134 -220.855794)
		(end 365.689134 -220.319854)
		(width 0.2032)
		(layer "F.Cu")
		(net "GND")
	)
	(segment
		(start 335.482692 -54.900068)
		(end 335.67878 -54.558946)
		(width 0.2032)
		(layer "F.Cu")
		(net "GND")
	)
	(segment
		(start 18.679414 -258.516628)
		(end 19.784314 -258.516628)
		(width 0.381)
		(layer "F.Cu")
		(net "GND")
	)
	(segment
		(start 457.221082 -219.41663)
		(end 456.116182 -219.41663)
		(width 0.381)
		(layer "F.Cu")
		(net "GND")
	)
	(segment
		(start 458.109828 -380.84887)
		(end 457.7461 -380.84887)
		(width 0.3556)
		(layer "F.Cu")
		(net "GND")
	)
	(segment
		(start 301.343314 -306.116736)
		(end 302.448214 -306.116736)
		(width 0.381)
		(layer "F.Cu")
		(net "GND")
	)
	(segment
		(start 449.677282 -205.816708)
		(end 448.572382 -205.816708)
		(width 0.381)
		(layer "F.Cu")
		(net "GND")
	)
	(segment
		(start 122.448066 -232.250488)
		(end 122.448066 -231.714548)
		(width 0.254)
		(layer "F.Cu")
		(net "GND")
	)
	(segment
		(start 15.684246 -292.516814)
		(end 16.789146 -292.516814)
		(width 0.381)
		(layer "F.Cu")
		(net "GND")
	)
	(segment
		(start 202.971146 -261.916672)
		(end 204.076046 -261.916672)
		(width 0.381)
		(layer "F.Cu")
		(net "GND")
	)
	(segment
		(start 5.694426 -97.778062)
		(end 6.2357 -97.236788)
		(width 0.3556)
		(layer "F.Cu")
		(net "GND")
	)
	(segment
		(start 60.947046 -290.816792)
		(end 62.051946 -290.816792)
		(width 0.381)
		(layer "F.Cu")
		(net "GND")
	)
	(segment
		(start 167.461946 -197.316598)
		(end 166.357046 -197.316598)
		(width 0.381)
		(layer "F.Cu")
		(net "GND")
	)
	(segment
		(start 334.675734 -217.600276)
		(end 334.675734 -217.06459)
		(width 0.2032)
		(layer "F.Cu")
		(net "GND")
	)
	(segment
		(start 117.859048 -278.614378)
		(end 117.859048 -279.150318)
		(width 0.254)
		(layer "F.Cu")
		(net "GND")
	)
	(segment
		(start 122.448066 -246.900446)
		(end 122.448066 -246.364506)
		(width 0.2032)
		(layer "F.Cu")
		(net "GND")
	)
	(segment
		(start 162.913314 -210.066636)
		(end 161.808414 -210.066636)
		(width 0.381)
		(layer "F.Cu")
		(net "GND")
	)
	(segment
		(start 444.472314 -231.316784)
		(end 445.577214 -231.316784)
		(width 0.381)
		(layer "F.Cu")
		(net "GND")
	)
	(segment
		(start 93.13545 -39.675308)
		(end 93.13545 -40.310308)
		(width 0.3556)
		(layer "F.Cu")
		(net "GND")
	)
	(segment
		(start 63.942214 -198.166736)
		(end 65.047114 -198.166736)
		(width 0.381)
		(layer "F.Cu")
		(net "GND")
	)
	(segment
		(start 33.767014 -312.91657)
		(end 34.871914 -312.91657)
		(width 0.381)
		(layer "F.Cu")
		(net "GND")
	)
	(segment
		(start 341.72398 -216.250774)
		(end 341.724234 -216.25052)
		(width 0.254)
		(layer "F.Cu")
		(net "GND")
	)
	(segment
		(start 372.847362 -289.195002)
		(end 372.847362 -289.807142)
		(width 0.2032)
		(layer "F.Cu")
		(net "GND")
	)
	(segment
		(start 410.853382 -194.766692)
		(end 409.748482 -194.766692)
		(width 0.381)
		(layer "F.Cu")
		(net "GND")
	)
	(segment
		(start 415.101786 -343.070688)
		(end 415.101786 -344.010996)
		(width 0.508)
		(layer "F.Cu")
		(net "GND")
	)
	(segment
		(start 39.420546 -285.716726)
		(end 38.315646 -285.716726)
		(width 0.381)
		(layer "F.Cu")
		(net "GND")
	)
	(segment
		(start 91.904312 -216.78646)
		(end 91.904312 -216.250774)
		(width 0.254)
		(layer "F.Cu")
		(net "GND")
	)
	(segment
		(start 20.889214 -213.46668)
		(end 19.784314 -213.46668)
		(width 0.381)
		(layer "F.Cu")
		(net "GND")
	)
	(segment
		(start 125.847094 -277.800562)
		(end 125.847348 -278.336502)
		(width 0.2032)
		(layer "F.Cu")
		(net "GND")
	)
	(segment
		(start 293.01059 -94.800674)
		(end 293.82466 -94.800674)
		(width 0.3556)
		(layer "F.Cu")
		(net "GND")
	)
	(segment
		(start 34.871914 -198.166736)
		(end 35.976814 -198.166736)
		(width 0.381)
		(layer "F.Cu")
		(net "GND")
	)
	(segment
		(start 383.545334 -228.45903)
		(end 383.545334 -228.99497)
		(width 0.254)
		(layer "F.Cu")
		(net "GND")
	)
	(segment
		(start 172.795946 -295.06672)
		(end 173.900846 -295.06672)
		(width 0.381)
		(layer "F.Cu")
		(net "GND")
	)
	(segment
		(start 352.641916 -273.730974)
		(end 352.641916 -274.26666)
		(width 0.2032)
		(layer "F.Cu")
		(net "GND")
	)
	(segment
		(start 384.124962 -279.428194)
		(end 384.124962 -279.964134)
		(width 0.2032)
		(layer "F.Cu")
		(net "GND")
	)
	(segment
		(start 135.24484 -260.430518)
		(end 135.245094 -260.430772)
		(width 0.254)
		(layer "F.Cu")
		(net "GND")
	)
	(segment
		(start 296.369994 -407.799794)
		(end 296.720768 -407.44902)
		(width 0.3556)
		(layer "F.Cu")
		(net "GND")
	)
	(segment
		(start 276.373082 -213.46668)
		(end 275.268182 -213.46668)
		(width 0.381)
		(layer "F.Cu")
		(net "GND")
	)
	(segment
		(start 94.723712 -216.78646)
		(end 94.723966 -216.786206)
		(width 0.254)
		(layer "F.Cu")
		(net "GND")
	)
	(segment
		(start 169.352214 -316.316614)
		(end 170.457114 -316.316614)
		(width 0.381)
		(layer "F.Cu")
		(net "GND")
	)
	(segment
		(start 181.444646 -199.01662)
		(end 182.549546 -199.01662)
		(width 0.381)
		(layer "F.Cu")
		(net "GND")
	)
	(segment
		(start 133.835648 -281.869896)
		(end 133.835648 -282.405582)
		(width 0.254)
		(layer "F.Cu")
		(net "GND")
	)
	(segment
		(start 348.30258 -228.1809)
		(end 348.302834 -228.180646)
		(width 0.2032)
		(layer "F.Cu")
		(net "GND")
	)
	(segment
		(start 421.840914 -244.916706)
		(end 422.945814 -244.916706)
		(width 0.381)
		(layer "F.Cu")
		(net "GND")
	)
	(segment
		(start 194.193414 -228.766624)
		(end 193.088514 -228.766624)
		(width 0.381)
		(layer "F.Cu")
		(net "GND")
	)
	(segment
		(start 285.150814 -229.616762)
		(end 286.255714 -229.616762)
		(width 0.381)
		(layer "F.Cu")
		(net "GND")
	)
	(segment
		(start 326.080374 -39.570152)
		(end 326.456294 -39.946072)
		(width 0.2032)
		(layer "F.Cu")
		(net "GND")
	)
	(segment
		(start 301.343314 -203.266802)
		(end 302.448214 -203.266802)
		(width 0.381)
		(layer "F.Cu")
		(net "GND")
	)
	(segment
		(start 52.023264 -144.267174)
		(end 52.500276 -144.744186)
		(width 0.2032)
		(layer "F.Cu")
		(net "GND")
	)
	(segment
		(start 272.273014 -233.016806)
		(end 271.168114 -233.016806)
		(width 0.381)
		(layer "F.Cu")
		(net "GND")
	)
	(segment
		(start 139.086336 -239.57534)
		(end 139.364212 -239.853216)
		(width 0.254)
		(layer "F.Cu")
		(net "GND")
	)
	(segment
		(start 198.276718 -76.016866)
		(end 198.276718 -75.27163)
		(width 0.3556)
		(layer "F.Cu")
		(net "GND")
	)
	(segment
		(start 108.461048 -271.011142)
		(end 108.460794 -271.011396)
		(width 0.2032)
		(layer "F.Cu")
		(net "GND")
	)
	(segment
		(start 104.231694 -279.96388)
		(end 104.231948 -279.964134)
		(width 0.2032)
		(layer "F.Cu")
		(net "GND")
	)
	(segment
		(start 256.080514 -268.71676)
		(end 257.185414 -268.71676)
		(width 0.381)
		(layer "F.Cu")
		(net "GND")
	)
	(segment
		(start 379.786134 -240.389156)
		(end 379.786134 -239.853216)
		(width 0.2032)
		(layer "F.Cu")
		(net "GND")
	)
	(segment
		(start 337.495134 -250.155964)
		(end 337.49488 -250.15571)
		(width 0.2032)
		(layer "F.Cu")
		(net "GND")
	)
	(segment
		(start 277.607014 -317.166752)
		(end 278.711914 -317.166752)
		(width 0.381)
		(layer "F.Cu")
		(net "GND")
	)
	(segment
		(start 383.545334 -241.481102)
		(end 383.545334 -242.017042)
		(width 0.254)
		(layer "F.Cu")
		(net "GND")
	)
	(segment
		(start 418.180012 -173.919642)
		(end 417.834572 -173.574202)
		(width 0.2032)
		(layer "F.Cu")
		(net "GND")
	)
	(segment
		(start 205.6892 -92.23375)
		(end 205.6892 -91.5924)
		(width 0.3556)
		(layer "F.Cu")
		(net "GND")
	)
	(segment
		(start 65.047114 -207.51673)
		(end 66.367914 -207.51673)
		(width 0.381)
		(layer "F.Cu")
		(net "GND")
	)
	(segment
		(start 215.719914 -272.966688)
		(end 216.824814 -272.966688)
		(width 0.381)
		(layer "F.Cu")
		(net "GND")
	)
	(segment
		(start 383.545334 -243.108988)
		(end 383.545334 -243.644928)
		(width 0.254)
		(layer "F.Cu")
		(net "GND")
	)
	(segment
		(start 373.622316 -95.141542)
		(end 373.622316 -96.264984)
		(width 0.3556)
		(layer "F.Cu")
		(net "GND")
	)
	(segment
		(start 355.82098 -223.297496)
		(end 355.82098 -222.76181)
		(width 0.254)
		(layer "F.Cu")
		(net "GND")
	)
	(segment
		(start 212.99805 -113.4872)
		(end 213.6902 -113.4872)
		(width 0.3556)
		(layer "F.Cu")
		(net "GND")
	)
	(segment
		(start 126.676912 -226.553268)
		(end 126.676912 -226.017582)
		(width 0.254)
		(layer "F.Cu")
		(net "GND")
	)
	(segment
		(start 441.028582 -202.416664)
		(end 442.133482 -202.416664)
		(width 0.381)
		(layer "F.Cu")
		(net "GND")
	)
	(segment
		(start 448.668902 -76.325222)
		(end 448.668902 -75.902566)
		(width 0.254)
		(layer "F.Cu")
		(net "GND")
	)
	(segment
		(start 137.124694 -279.428194)
		(end 137.124694 -279.964134)
		(width 0.2032)
		(layer "F.Cu")
		(net "GND")
	)
	(segment
		(start 12.240514 -219.41663)
		(end 13.345414 -219.41663)
		(width 0.381)
		(layer "F.Cu")
		(net "GND")
	)
	(segment
		(start 439.923682 -277.216616)
		(end 441.028582 -277.216616)
		(width 0.381)
		(layer "F.Cu")
		(net "GND")
	)
	(segment
		(start 105.641648 -284.033468)
		(end 105.641394 -284.033722)
		(width 0.254)
		(layer "F.Cu")
		(net "GND")
	)
	(segment
		(start 318.01816 -77.84592)
		(end 317.7921 -77.61986)
		(width 0.3556)
		(layer "F.Cu")
		(net "GND")
	)
	(segment
		(start 272.273014 -246.616728)
		(end 271.168114 -246.616728)
		(width 0.381)
		(layer "F.Cu")
		(net "GND")
	)
	(segment
		(start 92.954094 -257.175254)
		(end 92.954094 -256.639314)
		(width 0.2032)
		(layer "F.Cu")
		(net "GND")
	)
	(segment
		(start 417.292282 -301.01667)
		(end 418.397182 -301.01667)
		(width 0.381)
		(layer "F.Cu")
		(net "GND")
	)
	(segment
		(start 361.45978 -233.064304)
		(end 361.45978 -232.528618)
		(width 0.2032)
		(layer "F.Cu")
		(net "GND")
	)
	(segment
		(start 405.421338 -216.016586)
		(end 406.753314 -216.016586)
		(width 0.381)
		(layer "F.Cu")
		(net "GND")
	)
	(segment
		(start 354.521516 -272.103342)
		(end 354.521516 -272.639028)
		(width 0.2032)
		(layer "F.Cu")
		(net "GND")
	)
	(segment
		(start 19.784314 -222.816674)
		(end 18.679414 -222.816674)
		(width 0.381)
		(layer "F.Cu")
		(net "GND")
	)
	(segment
		(start 339.37448 -232.250234)
		(end 339.37448 -231.714548)
		(width 0.2032)
		(layer "F.Cu")
		(net "GND")
	)
	(segment
		(start 103.182166 -220.041724)
		(end 103.182166 -219.506038)
		(width 0.254)
		(layer "F.Cu")
		(net "GND")
	)
	(segment
		(start 132.315712 -219.506292)
		(end 132.315966 -219.506038)
		(width 0.254)
		(layer "F.Cu")
		(net "GND")
	)
	(segment
		(start 311.882282 -194.766692)
		(end 312.987182 -194.766692)
		(width 0.381)
		(layer "F.Cu")
		(net "GND")
	)
	(segment
		(start 368.618516 -280.242264)
		(end 368.618516 -280.77795)
		(width 0.254)
		(layer "F.Cu")
		(net "GND")
	)
	(segment
		(start 312.987182 -250.866656)
		(end 314.092082 -250.866656)
		(width 0.381)
		(layer "F.Cu")
		(net "GND")
	)
	(segment
		(start 384.124962 -262.058658)
		(end 384.124962 -261.522718)
		(width 0.254)
		(layer "F.Cu")
		(net "GND")
	)
	(segment
		(start 15.684246 -210.916774)
		(end 16.789146 -210.916774)
		(width 0.381)
		(layer "F.Cu")
		(net "GND")
	)
	(segment
		(start 378.846334 -230.622602)
		(end 378.84608 -230.622348)
		(width 0.2032)
		(layer "F.Cu")
		(net "GND")
	)
	(segment
		(start 449.677282 -295.916604)
		(end 448.572382 -295.916604)
		(width 0.381)
		(layer "F.Cu")
		(net "GND")
	)
	(segment
		(start 242.09375 -247.079008)
		(end 240.85042 -247.079008)
		(width 0.3556)
		(layer "F.Cu")
		(net "GND")
	)
	(segment
		(start 410.853382 -295.916604)
		(end 411.958282 -295.916604)
		(width 0.381)
		(layer "F.Cu")
		(net "GND")
	)
	(segment
		(start 381.195834 -228.180646)
		(end 381.195834 -227.64496)
		(width 0.2032)
		(layer "F.Cu")
		(net "GND")
	)
	(segment
		(start 344.183716 -263.96442)
		(end 344.183462 -263.964674)
		(width 0.254)
		(layer "F.Cu")
		(net "GND")
	)
	(segment
		(start 405.648414 -229.616762)
		(end 406.753314 -229.616762)
		(width 0.381)
		(layer "F.Cu")
		(net "GND")
	)
	(segment
		(start 311.882282 -198.166736)
		(end 312.987182 -198.166736)
		(width 0.381)
		(layer "F.Cu")
		(net "GND")
	)
	(segment
		(start 358.280716 -254.733298)
		(end 358.280462 -254.733552)
		(width 0.254)
		(layer "F.Cu")
		(net "GND")
	)
	(segment
		(start 263.624314 -204.96657)
		(end 264.729214 -204.96657)
		(width 0.381)
		(layer "F.Cu")
		(net "GND")
	)
	(segment
		(start 236.599984 -53.364892)
		(end 237.615984 -53.364892)
		(width 0.381)
		(layer "F.Cu")
		(net "GND")
	)
	(segment
		(start 338.499958 -50.850546)
		(end 338.499958 -50.050446)
		(width 0.2032)
		(layer "F.Cu")
		(net "GND")
	)
	(segment
		(start 196.532246 -199.01662)
		(end 197.637146 -199.01662)
		(width 0.381)
		(layer "F.Cu")
		(net "GND")
	)
	(segment
		(start 378.956062 -264.500106)
		(end 378.956062 -264.50036)
		(width 0.2032)
		(layer "F.Cu")
		(net "GND")
	)
	(segment
		(start 263.624314 -301.866808)
		(end 264.729214 -301.866808)
		(width 0.381)
		(layer "F.Cu")
		(net "GND")
	)
	(segment
		(start 19.784314 -205.816708)
		(end 18.679414 -205.816708)
		(width 0.381)
		(layer "F.Cu")
		(net "GND")
	)
	(segment
		(start 373.787162 -282.683966)
		(end 373.787416 -282.68422)
		(width 0.254)
		(layer "F.Cu")
		(net "GND")
	)
	(segment
		(start 29.666946 -199.01662)
		(end 30.771846 -199.01662)
		(width 0.381)
		(layer "F.Cu")
		(net "GND")
	)
	(segment
		(start 45.657008 -7.215124)
		(end 45.657008 -8.320024)
		(width 0.3556)
		(layer "F.Cu")
		(net "GND")
	)
	(segment
		(start 277.607014 -300.166786)
		(end 278.711914 -300.166786)
		(width 0.381)
		(layer "F.Cu")
		(net "GND")
	)
	(segment
		(start 354.991162 -282.683966)
		(end 354.991162 -283.219652)
		(width 0.254)
		(layer "F.Cu")
		(net "GND")
	)
	(segment
		(start 345.554554 -52.952396)
		(end 345.270836 -53.236114)
		(width 0.254)
		(layer "F.Cu")
		(net "GND")
	)
	(segment
		(start 191.983614 -310.366664)
		(end 193.088514 -310.366664)
		(width 0.381)
		(layer "F.Cu")
		(net "GND")
	)
	(segment
		(start 127.726694 -263.150604)
		(end 127.726694 -263.68629)
		(width 0.2032)
		(layer "F.Cu")
		(net "GND")
	)
	(segment
		(start 380.256034 -244.45849)
		(end 380.256034 -243.922804)
		(width 0.2032)
		(layer "F.Cu")
		(net "GND")
	)
	(segment
		(start 158.813246 -268.71676)
		(end 157.708346 -268.71676)
		(width 0.381)
		(layer "F.Cu")
		(net "GND")
	)
	(segment
		(start 304.338482 -280.61666)
		(end 305.443382 -280.61666)
		(width 0.381)
		(layer "F.Cu")
		(net "GND")
	)
	(segment
		(start 53.403246 -317.166752)
		(end 54.508146 -317.166752)
		(width 0.381)
		(layer "F.Cu")
		(net "GND")
	)
	(segment
		(start 132.315712 -234.69219)
		(end 132.315966 -234.691936)
		(width 0.2032)
		(layer "F.Cu")
		(net "GND")
	)
	(segment
		(start 275.268182 -286.56661)
		(end 274.163282 -286.56661)
		(width 0.381)
		(layer "F.Cu")
		(net "GND")
	)
	(segment
		(start 200.632314 -224.516696)
		(end 201.737214 -224.516696)
		(width 0.381)
		(layer "F.Cu")
		(net "GND")
	)
	(segment
		(start 286.255714 -315.46673)
		(end 287.360614 -315.46673)
		(width 0.381)
		(layer "F.Cu")
		(net "GND")
	)
	(segment
		(start 436.928514 -300.166786)
		(end 438.033414 -300.166786)
		(width 0.381)
		(layer "F.Cu")
		(net "GND")
	)
	(segment
		(start 429.384714 -315.46673)
		(end 430.489614 -315.46673)
		(width 0.381)
		(layer "F.Cu")
		(net "GND")
	)
	(segment
		(start 301.117 -25.7556)
		(end 301.117 -24.612854)
		(width 0.3556)
		(layer "F.Cu")
		(net "GND")
	)
	(segment
		(start 377.43638 -246.08663)
		(end 377.436634 -246.086376)
		(width 0.2032)
		(layer "F.Cu")
		(net "GND")
	)
	(segment
		(start 135.135112 -216.250774)
		(end 135.135366 -216.25052)
		(width 0.254)
		(layer "F.Cu")
		(net "GND")
	)
	(segment
		(start 129.606294 -268.033754)
		(end 129.606548 -268.569694)
		(width 0.2032)
		(layer "F.Cu")
		(net "GND")
	)
	(segment
		(start 421.840914 -276.366732)
		(end 420.736014 -276.366732)
		(width 0.381)
		(layer "F.Cu")
		(net "GND")
	)
	(segment
		(start 294.904414 -287.416748)
		(end 293.799514 -287.416748)
		(width 0.381)
		(layer "F.Cu")
		(net "GND")
	)
	(segment
		(start 441.028582 -211.766658)
		(end 442.133482 -211.766658)
		(width 0.381)
		(layer "F.Cu")
		(net "GND")
	)
	(segment
		(start 254.975614 -248.31675)
		(end 256.080514 -248.31675)
		(width 0.381)
		(layer "F.Cu")
		(net "GND")
	)
	(segment
		(start 329.441048 -55.968646)
		(end 329.980036 -55.968646)
		(width 0.2032)
		(layer "F.Cu")
		(net "GND")
	)
	(segment
		(start 110.700566 -223.297496)
		(end 110.700566 -222.761556)
		(width 0.254)
		(layer "F.Cu")
		(net "GND")
	)
	(segment
		(start 199.527414 -291.666676)
		(end 200.632314 -291.666676)
		(width 0.381)
		(layer "F.Cu")
		(net "GND")
	)
	(segment
		(start 133.255512 -242.830858)
		(end 133.255512 -242.295172)
		(width 0.2032)
		(layer "F.Cu")
		(net "GND")
	)
	(segment
		(start 307.782214 -234.716574)
		(end 308.887114 -234.716574)
		(width 0.381)
		(layer "F.Cu")
		(net "GND")
	)
	(segment
		(start 294.904414 -272.116804)
		(end 293.799514 -272.116804)
		(width 0.381)
		(layer "F.Cu")
		(net "GND")
	)
	(segment
		(start 412.12389 -235.591604)
		(end 410.878274 -235.591604)
		(width 0.381)
		(layer "F.Cu")
		(net "GND")
	)
	(segment
		(start 387.481318 -270.458438)
		(end 387.493256 -270.470376)
		(width 0.254)
		(layer "F.Cu")
		(net "GND")
	)
	(segment
		(start 427.602904 -120.238012)
		(end 427.729904 -120.365012)
		(width 0.381)
		(layer "F.Cu")
		(net "GND")
	)
	(segment
		(start 176.555654 -111.375444)
		(end 176.155604 -110.975394)
		(width 0.3556)
		(layer "F.Cu")
		(net "GND")
	)
	(segment
		(start 383.914904 -73.15962)
		(end 383.914904 -73.920858)
		(width 0.3556)
		(layer "F.Cu")
		(net "GND")
	)
	(segment
		(start 336.195162 -258.2672)
		(end 336.195162 -258.80314)
		(width 0.2032)
		(layer "F.Cu")
		(net "GND")
	)
	(segment
		(start 34.871914 -286.56661)
		(end 33.767014 -286.56661)
		(width 0.381)
		(layer "F.Cu")
		(net "GND")
	)
	(segment
		(start 344.54338 -216.78646)
		(end 344.54338 -216.250774)
		(width 0.254)
		(layer "F.Cu")
		(net "GND")
	)
	(segment
		(start 345.953334 -248.528078)
		(end 345.953334 -247.992138)
		(width 0.2032)
		(layer "F.Cu")
		(net "GND")
	)
	(segment
		(start 335.14538 -232.528618)
		(end 335.145634 -232.528364)
		(width 0.254)
		(layer "F.Cu")
		(net "GND")
	)
	(segment
		(start 193.088514 -286.56661)
		(end 194.193414 -286.56661)
		(width 0.381)
		(layer "F.Cu")
		(net "GND")
	)
	(segment
		(start 137.014712 -220.041978)
		(end 137.014712 -219.506038)
		(width 0.2032)
		(layer "F.Cu")
		(net "GND")
	)
	(segment
		(start 132.315966 -244.45849)
		(end 132.315966 -243.922804)
		(width 0.2032)
		(layer "F.Cu")
		(net "GND")
	)
	(segment
		(start 413.080962 -285.716726)
		(end 414.297114 -285.716726)
		(width 0.381)
		(layer "F.Cu")
		(net "GND")
	)
	(segment
		(start 463.659982 -239.81664)
		(end 464.764882 -239.81664)
		(width 0.381)
		(layer "F.Cu")
		(net "GND")
	)
	(segment
		(start 432.379882 -232.166668)
		(end 433.484782 -232.166668)
		(width 0.381)
		(layer "F.Cu")
		(net "GND")
	)
	(segment
		(start 433.484782 -299.316648)
		(end 434.589682 -299.316648)
		(width 0.381)
		(layer "F.Cu")
		(net "GND")
	)
	(segment
		(start 383.545334 -219.228162)
		(end 383.545334 -218.692222)
		(width 0.2032)
		(layer "F.Cu")
		(net "GND")
	)
	(segment
		(start 304.338482 -194.766692)
		(end 305.443382 -194.766692)
		(width 0.381)
		(layer "F.Cu")
		(net "GND")
	)
	(segment
		(start 455.011282 -241.516662)
		(end 456.116182 -241.516662)
		(width 0.381)
		(layer "F.Cu")
		(net "GND")
	)
	(segment
		(start 191.983614 -277.216616)
		(end 193.088514 -277.216616)
		(width 0.381)
		(layer "F.Cu")
		(net "GND")
	)
	(segment
		(start 336.085434 -240.667286)
		(end 336.085434 -241.203226)
		(width 0.254)
		(layer "F.Cu")
		(net "GND")
	)
	(segment
		(start 29.223462 -138.37666)
		(end 29.22524 -138.378438)
		(width 0.3556)
		(layer "F.Cu")
		(net "GND")
	)
	(segment
		(start 195.427346 -248.31675)
		(end 196.532246 -248.31675)
		(width 0.381)
		(layer "F.Cu")
		(net "GND")
	)
	(segment
		(start 59.626246 -217.716608)
		(end 60.947046 -217.716608)
		(width 0.381)
		(layer "F.Cu")
		(net "GND")
	)
	(segment
		(start 421.840914 -296.766742)
		(end 420.736014 -296.766742)
		(width 0.381)
		(layer "F.Cu")
		(net "GND")
	)
	(segment
		(start 419.802818 -210.066636)
		(end 418.397182 -210.066636)
		(width 0.381)
		(layer "F.Cu")
		(net "GND")
	)
	(segment
		(start 57.503314 -228.766624)
		(end 58.608214 -228.766624)
		(width 0.381)
		(layer "F.Cu")
		(net "GND")
	)
	(segment
		(start 123.387612 -250.15571)
		(end 123.387612 -249.620024)
		(width 0.2032)
		(layer "F.Cu")
		(net "GND")
	)
	(segment
		(start 214.615014 -233.86669)
		(end 215.719914 -233.86669)
		(width 0.381)
		(layer "F.Cu")
		(net "GND")
	)
	(segment
		(start 254.975614 -246.616728)
		(end 256.080514 -246.616728)
		(width 0.381)
		(layer "F.Cu")
		(net "GND")
	)
	(segment
		(start 410.853382 -264.466578)
		(end 411.958282 -264.466578)
		(width 0.381)
		(layer "F.Cu")
		(net "GND")
	)
	(segment
		(start 337.604862 -277.522432)
		(end 337.604862 -276.986492)
		(width 0.2032)
		(layer "F.Cu")
		(net "GND")
	)
	(segment
		(start 23.228046 -195.616576)
		(end 24.332946 -195.616576)
		(width 0.381)
		(layer "F.Cu")
		(net "GND")
	)
	(segment
		(start 300.238414 -279.766776)
		(end 301.343314 -279.766776)
		(width 0.381)
		(layer "F.Cu")
		(net "GND")
	)
	(segment
		(start 110.230666 -227.367084)
		(end 110.230666 -226.831144)
		(width 0.2032)
		(layer "F.Cu")
		(net "GND")
	)
	(segment
		(start 347.36278 -216.250774)
		(end 347.363034 -216.25052)
		(width 0.254)
		(layer "F.Cu")
		(net "GND")
	)
	(segment
		(start 7.495286 -100.691696)
		(end 7.899146 -100.287836)
		(width 0.3556)
		(layer "F.Cu")
		(net "GND")
	)
	(segment
		(start 349.24238 -241.203226)
		(end 349.242634 -241.202972)
		(width 0.254)
		(layer "F.Cu")
		(net "GND")
	)
	(segment
		(start 305.443382 -282.316682)
		(end 306.548282 -282.316682)
		(width 0.381)
		(layer "F.Cu")
		(net "GND")
	)
	(segment
		(start 113.62944 -263.68629)
		(end 113.62944 -263.686544)
		(width 0.254)
		(layer "F.Cu")
		(net "GND")
	)
	(segment
		(start 202.971146 -276.366732)
		(end 204.076046 -276.366732)
		(width 0.381)
		(layer "F.Cu")
		(net "GND")
	)
	(segment
		(start 94.833948 -271.289526)
		(end 94.833948 -271.825212)
		(width 0.2032)
		(layer "F.Cu")
		(net "GND")
	)
	(segment
		(start 38.315646 -309.51678)
		(end 37.210746 -309.51678)
		(width 0.381)
		(layer "F.Cu")
		(net "GND")
	)
	(segment
		(start 139.83843 -38.049708)
		(end 139.83843 -37.414708)
		(width 0.3556)
		(layer "F.Cu")
		(net "GND")
	)
	(segment
		(start 113.519712 -232.528618)
		(end 113.519966 -232.528364)
		(width 0.254)
		(layer "F.Cu")
		(net "GND")
	)
	(segment
		(start 386.474716 -280.242264)
		(end 386.474716 -280.778204)
		(width 0.2032)
		(layer "F.Cu")
		(net "GND")
	)
	(segment
		(start 123.249944 -360.132376)
		(end 122.939048 -360.443272)
		(width 0.3556)
		(layer "F.Cu")
		(net "GND")
	)
	(segment
		(start 336.665316 -283.497782)
		(end 336.665316 -284.033722)
		(width 0.254)
		(layer "F.Cu")
		(net "GND")
	)
	(segment
		(start 48.854614 -306.96662)
		(end 49.959514 -306.96662)
		(width 0.381)
		(layer "F.Cu")
		(net "GND")
	)
	(segment
		(start 406.524714 -365.294926)
		(end 406.524714 -364.151926)
		(width 0.381)
		(layer "F.Cu")
		(net "GND")
	)
	(segment
		(start 275.268182 -200.716642)
		(end 274.163282 -200.716642)
		(width 0.381)
		(layer "F.Cu")
		(net "GND")
	)
	(segment
		(start 129.966212 -240.388902)
		(end 129.966212 -239.853216)
		(width 0.2032)
		(layer "F.Cu")
		(net "GND")
	)
	(segment
		(start 91.434666 -223.575626)
		(end 91.434666 -224.111566)
		(width 0.2032)
		(layer "F.Cu")
		(net "GND")
	)
	(segment
		(start 115.039648 -268.84757)
		(end 115.039394 -269.38351)
		(width 0.2032)
		(layer "F.Cu")
		(net "GND")
	)
	(segment
		(start 44.754546 -212.616796)
		(end 45.859446 -212.616796)
		(width 0.381)
		(layer "F.Cu")
		(net "GND")
	)
	(segment
		(start 42.415714 -196.466714)
		(end 43.520614 -196.466714)
		(width 0.381)
		(layer "F.Cu")
		(net "GND")
	)
	(segment
		(start 94.833694 -279.428194)
		(end 94.833694 -279.964134)
		(width 0.254)
		(layer "F.Cu")
		(net "GND")
	)
	(segment
		(start 118.218712 -216.78646)
		(end 118.218712 -216.250774)
		(width 0.254)
		(layer "F.Cu")
		(net "GND")
	)
	(segment
		(start 182.549546 -273.816572)
		(end 181.444646 -273.816572)
		(width 0.381)
		(layer "F.Cu")
		(net "GND")
	)
	(segment
		(start 7.035546 -278.066754)
		(end 8.140446 -278.066754)
		(width 0.381)
		(layer "F.Cu")
		(net "GND")
	)
	(segment
		(start 171.562014 -289.966654)
		(end 170.457114 -289.966654)
		(width 0.381)
		(layer "F.Cu")
		(net "GND")
	)
	(segment
		(start 202.971146 -311.216802)
		(end 204.076046 -311.216802)
		(width 0.381)
		(layer "F.Cu")
		(net "GND")
	)
	(segment
		(start 365.689134 -227.367084)
		(end 365.689134 -226.831144)
		(width 0.2032)
		(layer "F.Cu")
		(net "GND")
	)
	(segment
		(start 193.088514 -198.166736)
		(end 191.983614 -198.166736)
		(width 0.381)
		(layer "F.Cu")
		(net "GND")
	)
	(segment
		(start 297.899582 -289.966654)
		(end 299.004482 -289.966654)
		(width 0.381)
		(layer "F.Cu")
		(net "GND")
	)
	(segment
		(start 14.579346 -304.416714)
		(end 15.684246 -304.416714)
		(width 0.381)
		(layer "F.Cu")
		(net "GND")
	)
	(segment
		(start 425.940982 -216.866724)
		(end 427.045882 -216.866724)
		(width 0.381)
		(layer "F.Cu")
		(net "GND")
	)
	(segment
		(start 39.420546 -210.916774)
		(end 38.315646 -210.916774)
		(width 0.381)
		(layer "F.Cu")
		(net "GND")
	)
	(segment
		(start 171.8564 -219.41663)
		(end 170.457114 -219.41663)
		(width 0.381)
		(layer "F.Cu")
		(net "GND")
	)
	(segment
		(start 7.525512 -101.095302)
		(end 7.495286 -101.125528)
		(width 0.3556)
		(layer "F.Cu")
		(net "GND")
	)
	(segment
		(start 347.473016 -271.289526)
		(end 347.473016 -271.825212)
		(width 0.2032)
		(layer "F.Cu")
		(net "GND")
	)
	(segment
		(start 307.782214 -204.96657)
		(end 308.887114 -204.96657)
		(width 0.381)
		(layer "F.Cu")
		(net "GND")
	)
	(segment
		(start 339.374734 -242.017042)
		(end 339.37448 -242.016788)
		(width 0.2032)
		(layer "F.Cu")
		(net "GND")
	)
	(segment
		(start 350.292162 -277.800562)
		(end 350.292162 -278.336248)
		(width 0.254)
		(layer "F.Cu")
		(net "GND")
	)
	(segment
		(start 135.135112 -222.76181)
		(end 135.135366 -222.761556)
		(width 0.254)
		(layer "F.Cu")
		(net "GND")
	)
	(segment
		(start 428.279814 -317.166752)
		(end 429.384714 -317.166752)
		(width 0.381)
		(layer "F.Cu")
		(net "GND")
	)
	(segment
		(start 214.615014 -314.616592)
		(end 215.719914 -314.616592)
		(width 0.381)
		(layer "F.Cu")
		(net "GND")
	)
	(segment
		(start 211.619846 -214.316564)
		(end 212.724746 -214.316564)
		(width 0.381)
		(layer "F.Cu")
		(net "GND")
	)
	(segment
		(start 184.439814 -262.76681)
		(end 185.544714 -262.76681)
		(width 0.381)
		(layer "F.Cu")
		(net "GND")
	)
	(segment
		(start 427.045882 -297.616626)
		(end 425.940982 -297.616626)
		(width 0.381)
		(layer "F.Cu")
		(net "GND")
	)
	(segment
		(start 77.683106 -345.055952)
		(end 77.997304 -344.741754)
		(width 0.1778)
		(layer "F.Cu")
		(net "GND")
	)
	(segment
		(start 374.147334 -248.528078)
		(end 374.147334 -247.992138)
		(width 0.2032)
		(layer "F.Cu")
		(net "GND")
	)
	(segment
		(start 170.457114 -202.416664)
		(end 169.352214 -202.416664)
		(width 0.381)
		(layer "F.Cu")
		(net "GND")
	)
	(segment
		(start 342.193118 -53.618892)
		(end 342.19134 -53.619146)
		(width 0.2032)
		(layer "F.Cu")
		(net "GND")
	)
	(segment
		(start 372.53164 -68.930012)
		(end 372.53164 -69.565012)
		(width 0.3556)
		(layer "F.Cu")
		(net "GND")
	)
	(segment
		(start 342.773762 -268.033754)
		(end 342.773762 -268.569694)
		(width 0.2032)
		(layer "F.Cu")
		(net "GND")
	)
	(segment
		(start 363.809534 -232.250488)
		(end 363.80928 -232.250234)
		(width 0.2032)
		(layer "F.Cu")
		(net "GND")
	)
	(segment
		(start 109.760512 -215.158574)
		(end 109.760512 -214.546434)
		(width 0.254)
		(layer "F.Cu")
		(net "GND")
	)
	(segment
		(start 302.8442 -24.7396)
		(end 302.4378 -25.146)
		(width 0.3556)
		(layer "F.Cu")
		(net "GND")
	)
	(segment
		(start 382.135634 -247.714262)
		(end 382.135634 -247.178322)
		(width 0.2032)
		(layer "F.Cu")
		(net "GND")
	)
	(segment
		(start 293.799514 -287.416748)
		(end 292.694614 -287.416748)
		(width 0.381)
		(layer "F.Cu")
		(net "GND")
	)
	(segment
		(start 111.640112 -220.041978)
		(end 111.640112 -219.506292)
		(width 0.254)
		(layer "F.Cu")
		(net "GND")
	)
	(segment
		(start 109.760766 -220.041724)
		(end 109.760766 -219.506038)
		(width 0.254)
		(layer "F.Cu")
		(net "GND")
	)
	(segment
		(start 53.403246 -292.516814)
		(end 54.724046 -292.516814)
		(width 0.381)
		(layer "F.Cu")
		(net "GND")
	)
	(segment
		(start 293.799514 -250.016772)
		(end 292.694614 -250.016772)
		(width 0.381)
		(layer "F.Cu")
		(net "GND")
	)
	(segment
		(start 421.840914 -307.816758)
		(end 420.736014 -307.816758)
		(width 0.381)
		(layer "F.Cu")
		(net "GND")
	)
	(segment
		(start 137.00633 -26.251408)
		(end 137.02411 -26.269188)
		(width 0.3556)
		(layer "F.Cu")
		(net "GND")
	)
	(segment
		(start 370.388134 -238.761524)
		(end 370.38788 -238.76127)
		(width 0.2032)
		(layer "F.Cu")
		(net "GND")
	)
	(segment
		(start 339.37448 -237.133638)
		(end 339.37448 -236.597952)
		(width 0.2032)
		(layer "F.Cu")
		(net "GND")
	)
	(segment
		(start 57.503314 -210.066636)
		(end 56.182514 -210.066636)
		(width 0.381)
		(layer "F.Cu")
		(net "GND")
	)
	(segment
		(start 357.700834 -220.041724)
		(end 357.700834 -219.506038)
		(width 0.254)
		(layer "F.Cu")
		(net "GND")
	)
	(segment
		(start 115.869466 -227.367084)
		(end 115.869466 -226.831144)
		(width 0.2032)
		(layer "F.Cu")
		(net "GND")
	)
	(segment
		(start 29.666946 -279.766776)
		(end 30.771846 -279.766776)
		(width 0.381)
		(layer "F.Cu")
		(net "GND")
	)
	(segment
		(start 134.868412 -41.840404)
		(end 133.928612 -41.840404)
		(width 0.3556)
		(layer "F.Cu")
		(net "GND")
	)
	(segment
		(start 96.243648 -287.288986)
		(end 96.243394 -287.28924)
		(width 0.254)
		(layer "F.Cu")
		(net "GND")
	)
	(segment
		(start 196.307964 -79.135732)
		(end 196.229478 -79.057246)
		(width 0.3556)
		(layer "F.Cu")
		(net "GND")
	)
	(segment
		(start 267.724382 -314.616592)
		(end 268.829282 -314.616592)
		(width 0.381)
		(layer "F.Cu")
		(net "GND")
	)
	(segment
		(start 441.028582 -288.266632)
		(end 442.133482 -288.266632)
		(width 0.381)
		(layer "F.Cu")
		(net "GND")
	)
	(segment
		(start 211.619846 -276.366732)
		(end 210.514946 -276.366732)
		(width 0.381)
		(layer "F.Cu")
		(net "GND")
	)
	(segment
		(start 11.135614 -239.81664)
		(end 12.240514 -239.81664)
		(width 0.381)
		(layer "F.Cu")
		(net "GND")
	)
	(segment
		(start 38.315646 -240.666778)
		(end 37.210746 -240.666778)
		(width 0.381)
		(layer "F.Cu")
		(net "GND")
	)
	(segment
		(start 380.72568 -232.250234)
		(end 380.72568 -231.714548)
		(width 0.2032)
		(layer "F.Cu")
		(net "GND")
	)
	(segment
		(start 145.175224 -94.89059)
		(end 145.175224 -95.243396)
		(width 0.3556)
		(layer "F.Cu")
		(net "GND")
	)
	(segment
		(start 457.221082 -284.866588)
		(end 456.116182 -284.866588)
		(width 0.381)
		(layer "F.Cu")
		(net "GND")
	)
	(segment
		(start 466.5345 -95.607632)
		(end 466.5345 -94.902528)
		(width 0.3556)
		(layer "F.Cu")
		(net "GND")
	)
	(segment
		(start 395.02334 -160.53054)
		(end 395.550898 -160.53054)
		(width 0.3556)
		(layer "F.Cu")
		(net "GND")
	)
	(segment
		(start 99.24542 -100.292408)
		(end 99.46386 -100.073968)
		(width 0.3556)
		(layer "F.Cu")
		(net "GND")
	)
	(segment
		(start 282.811982 -194.766692)
		(end 283.916882 -194.766692)
		(width 0.381)
		(layer "F.Cu")
		(net "GND")
	)
	(segment
		(start 125.847348 -282.68422)
		(end 125.847348 -283.219906)
		(width 0.254)
		(layer "F.Cu")
		(net "GND")
	)
	(segment
		(start 111.21136 -31.837884)
		(end 110.57636 -31.837884)
		(width 0.3556)
		(layer "F.Cu")
		(net "GND")
	)
	(segment
		(start 95.773494 -279.428194)
		(end 95.773494 -279.96388)
		(width 0.254)
		(layer "F.Cu")
		(net "GND")
	)
	(segment
		(start 271.168114 -281.466798)
		(end 272.273014 -281.466798)
		(width 0.381)
		(layer "F.Cu")
		(net "GND")
	)
	(segment
		(start 44.754546 -273.816572)
		(end 45.859446 -273.816572)
		(width 0.381)
		(layer "F.Cu")
		(net "GND")
	)
	(segment
		(start 257.27533 -52.507642)
		(end 256.134108 -51.36642)
		(width 0.254)
		(layer "F.Cu")
		(net "GND")
	)
	(segment
		(start 191.983614 -297.616626)
		(end 193.088514 -297.616626)
		(width 0.381)
		(layer "F.Cu")
		(net "GND")
	)
	(segment
		(start 463.659982 -267.866622)
		(end 464.764882 -267.866622)
		(width 0.381)
		(layer "F.Cu")
		(net "GND")
	)
	(segment
		(start 256.080514 -242.3668)
		(end 257.185414 -242.3668)
		(width 0.381)
		(layer "F.Cu")
		(net "GND")
	)
	(segment
		(start 346.42298 -226.017582)
		(end 346.423234 -226.017328)
		(width 0.254)
		(layer "F.Cu")
		(net "GND")
	)
	(segment
		(start 115.10391 -363.508036)
		(end 115.10391 -363.80293)
		(width 0.4572)
		(layer "F.Cu")
		(net "GND")
	)
	(segment
		(start 368.97818 -226.553268)
		(end 368.97818 -226.017582)
		(width 0.254)
		(layer "F.Cu")
		(net "GND")
	)
	(segment
		(start 117.278912 -229.808786)
		(end 117.279166 -229.808532)
		(width 0.2032)
		(layer "F.Cu")
		(net "GND")
	)
	(segment
		(start 341.72398 -247.714262)
		(end 341.72398 -247.178576)
		(width 0.2032)
		(layer "F.Cu")
		(net "GND")
	)
	(segment
		(start 337.49488 -232.250234)
		(end 337.49488 -231.714548)
		(width 0.2032)
		(layer "F.Cu")
		(net "GND")
	)
	(segment
		(start 334.315562 -266.405868)
		(end 335.255362 -266.941808)
		(width 0.2032)
		(layer "F.Cu")
		(net "GND")
	)
	(segment
		(start 254.975614 -307.816758)
		(end 256.080514 -307.816758)
		(width 0.381)
		(layer "F.Cu")
		(net "GND")
	)
	(segment
		(start 113.519712 -246.08663)
		(end 113.519712 -245.551452)
		(width 0.254)
		(layer "F.Cu")
		(net "GND")
	)
	(segment
		(start 100.002848 -284.033468)
		(end 100.002594 -284.033722)
		(width 0.254)
		(layer "F.Cu")
		(net "GND")
	)
	(segment
		(start 452.016114 -268.71676)
		(end 450.911214 -268.71676)
		(width 0.381)
		(layer "F.Cu")
		(net "GND")
	)
	(segment
		(start 137.484866 -237.133892)
		(end 136.544812 -236.597952)
		(width 0.254)
		(layer "F.Cu")
		(net "GND")
	)
	(segment
		(start 336.085434 -239.0394)
		(end 336.085434 -239.57534)
		(width 0.254)
		(layer "F.Cu")
		(net "GND")
	)
	(segment
		(start 208.176114 -198.166736)
		(end 209.281014 -198.166736)
		(width 0.381)
		(layer "F.Cu")
		(net "GND")
	)
	(segment
		(start 101.412294 -263.150604)
		(end 101.412294 -263.686544)
		(width 0.254)
		(layer "F.Cu")
		(net "GND")
	)
	(segment
		(start 132.895848 -284.033468)
		(end 132.895594 -284.033722)
		(width 0.254)
		(layer "F.Cu")
		(net "GND")
	)
	(segment
		(start 45.859446 -301.866808)
		(end 46.964346 -301.866808)
		(width 0.381)
		(layer "F.Cu")
		(net "GND")
	)
	(segment
		(start 331.608176 -42.811446)
		(end 331.067918 -42.811446)
		(width 0.2032)
		(layer "F.Cu")
		(net "GND")
	)
	(segment
		(start 444.472314 -208.366614)
		(end 443.367414 -208.366614)
		(width 0.381)
		(layer "F.Cu")
		(net "GND")
	)
	(segment
		(start 30.771846 -306.116736)
		(end 31.876746 -306.116736)
		(width 0.381)
		(layer "F.Cu")
		(net "GND")
	)
	(segment
		(start 49.959514 -222.816674)
		(end 51.064414 -222.816674)
		(width 0.381)
		(layer "F.Cu")
		(net "GND")
	)
	(segment
		(start 311.882282 -308.666642)
		(end 312.987182 -308.666642)
		(width 0.381)
		(layer "F.Cu")
		(net "GND")
	)
	(segment
		(start 202.971146 -246.616728)
		(end 204.076046 -246.616728)
		(width 0.381)
		(layer "F.Cu")
		(net "GND")
	)
	(segment
		(start 30.771846 -268.71676)
		(end 31.876746 -268.71676)
		(width 0.381)
		(layer "F.Cu")
		(net "GND")
	)
	(segment
		(start 305.443382 -286.56661)
		(end 306.548282 -286.56661)
		(width 0.381)
		(layer "F.Cu")
		(net "GND")
	)
	(segment
		(start 144.6022 -105.100628)
		(end 144.6022 -104.516428)
		(width 0.3556)
		(layer "F.Cu")
		(net "GND")
	)
	(segment
		(start 314.710572 -54.219348)
		(end 314.710572 -55.235348)
		(width 0.3556)
		(layer "F.Cu")
		(net "GND")
	)
	(segment
		(start 367.568734 -227.367084)
		(end 367.568734 -226.831144)
		(width 0.2032)
		(layer "F.Cu")
		(net "GND")
	)
	(segment
		(start 34.871914 -261.066788)
		(end 35.976814 -261.066788)
		(width 0.381)
		(layer "F.Cu")
		(net "GND")
	)
	(segment
		(start 332.796134 -242.017042)
		(end 332.32598 -242.294918)
		(width 0.254)
		(layer "F.Cu")
		(net "GND")
	)
	(segment
		(start 184.439814 -200.716642)
		(end 185.544714 -200.716642)
		(width 0.381)
		(layer "F.Cu")
		(net "GND")
	)
	(segment
		(start 429.384714 -195.616576)
		(end 430.489614 -195.616576)
		(width 0.381)
		(layer "F.Cu")
		(net "GND")
	)
	(segment
		(start 378.37618 -226.553268)
		(end 378.37618 -226.017582)
		(width 0.254)
		(layer "F.Cu")
		(net "GND")
	)
	(segment
		(start 53.403246 -260.21665)
		(end 54.508146 -260.21665)
		(width 0.381)
		(layer "F.Cu")
		(net "GND")
	)
	(segment
		(start 60.947046 -216.016586)
		(end 62.051946 -216.016586)
		(width 0.381)
		(layer "F.Cu")
		(net "GND")
	)
	(segment
		(start 104.701594 -268.847824)
		(end 104.701594 -269.38351)
		(width 0.254)
		(layer "F.Cu")
		(net "GND")
	)
	(segment
		(start 131.016248 -265.592306)
		(end 131.016248 -266.127992)
		(width 0.254)
		(layer "F.Cu")
		(net "GND")
	)
	(segment
		(start 414.297114 -296.766742)
		(end 415.402014 -296.766742)
		(width 0.381)
		(layer "F.Cu")
		(net "GND")
	)
	(segment
		(start 96.603312 -216.78646)
		(end 96.603312 -216.250774)
		(width 0.254)
		(layer "F.Cu")
		(net "GND")
	)
	(segment
		(start 193.088514 -288.266632)
		(end 194.193414 -288.266632)
		(width 0.381)
		(layer "F.Cu")
		(net "GND")
	)
	(segment
		(start 342.66378 -226.553268)
		(end 342.66378 -226.017582)
		(width 0.254)
		(layer "F.Cu")
		(net "GND")
	)
	(segment
		(start 84.856066 -246.900446)
		(end 84.386166 -247.178322)
		(width 0.2032)
		(layer "F.Cu")
		(net "GND")
	)
	(segment
		(start 286.255714 -234.716574)
		(end 287.360614 -234.716574)
		(width 0.381)
		(layer "F.Cu")
		(net "GND")
	)
	(segment
		(start 286.255714 -311.216802)
		(end 287.360614 -311.216802)
		(width 0.381)
		(layer "F.Cu")
		(net "GND")
	)
	(segment
		(start 153.01722 -39.080948)
		(end 152.911556 -38.975284)
		(width 0.3556)
		(layer "F.Cu")
		(net "GND")
	)
	(segment
		(start 158.813246 -281.466798)
		(end 157.708346 -281.466798)
		(width 0.381)
		(layer "F.Cu")
		(net "GND")
	)
	(segment
		(start 200.632314 -241.516662)
		(end 201.737214 -241.516662)
		(width 0.381)
		(layer "F.Cu")
		(net "GND")
	)
	(segment
		(start 296.578782 -275.516594)
		(end 297.899582 -275.516594)
		(width 0.381)
		(layer "F.Cu")
		(net "GND")
	)
	(segment
		(start 89.555066 -246.900446)
		(end 89.554812 -246.900192)
		(width 0.2032)
		(layer "F.Cu")
		(net "GND")
	)
	(segment
		(start 290.355782 -244.066568)
		(end 291.460682 -244.066568)
		(width 0.381)
		(layer "F.Cu")
		(net "GND")
	)
	(segment
		(start 126.676912 -233.064304)
		(end 126.676912 -232.528364)
		(width 0.2032)
		(layer "F.Cu")
		(net "GND")
	)
	(segment
		(start 436.928514 -244.916706)
		(end 438.033414 -244.916706)
		(width 0.381)
		(layer "F.Cu")
		(net "GND")
	)
	(segment
		(start 43.520614 -194.766692)
		(end 42.415714 -194.766692)
		(width 0.381)
		(layer "F.Cu")
		(net "GND")
	)
	(segment
		(start 306.0192 -26.5684)
		(end 306.2224 -26.3652)
		(width 0.3556)
		(layer "F.Cu")
		(net "GND")
	)
	(segment
		(start 369.558316 -281.869896)
		(end 369.558316 -282.405582)
		(width 0.254)
		(layer "F.Cu")
		(net "GND")
	)
	(segment
		(start 342.773762 -278.336248)
		(end 342.774016 -278.336502)
		(width 0.2032)
		(layer "F.Cu")
		(net "GND")
	)
	(segment
		(start 15.684246 -263.616694)
		(end 16.789146 -263.616694)
		(width 0.381)
		(layer "F.Cu")
		(net "GND")
	)
	(segment
		(start 444.472314 -313.766708)
		(end 445.577214 -313.766708)
		(width 0.381)
		(layer "F.Cu")
		(net "GND")
	)
	(segment
		(start 337.604862 -262.336534)
		(end 337.604862 -262.872474)
		(width 0.2032)
		(layer "F.Cu")
		(net "GND")
	)
	(segment
		(start 107.880912 -229.808786)
		(end 107.881166 -229.808532)
		(width 0.2032)
		(layer "F.Cu")
		(net "GND")
	)
	(segment
		(start 271.168114 -306.116736)
		(end 270.063214 -306.116736)
		(width 0.381)
		(layer "F.Cu")
		(net "GND")
	)
	(segment
		(start 136.655048 -281.869896)
		(end 136.655048 -282.405582)
		(width 0.254)
		(layer "F.Cu")
		(net "GND")
	)
	(segment
		(start 129.496312 -216.78646)
		(end 129.496312 -216.250774)
		(width 0.254)
		(layer "F.Cu")
		(net "GND")
	)
	(segment
		(start 445.577214 -217.716608)
		(end 444.472314 -217.716608)
		(width 0.381)
		(layer "F.Cu")
		(net "GND")
	)
	(segment
		(start 412.964122 -313.766708)
		(end 414.297114 -313.766708)
		(width 0.381)
		(layer "F.Cu")
		(net "GND")
	)
	(segment
		(start 152.075896 -39.450772)
		(end 152.075896 -38.975284)
		(width 0.3556)
		(layer "F.Cu")
		(net "GND")
	)
	(segment
		(start 456.052936 -380.085854)
		(end 456.179936 -380.085854)
		(width 0.381)
		(layer "F.Cu")
		(net "GND")
	)
	(segment
		(start 272.273014 -267.016738)
		(end 271.168114 -267.016738)
		(width 0.381)
		(layer "F.Cu")
		(net "GND")
	)
	(segment
		(start 170.457114 -210.066636)
		(end 171.86275 -210.066636)
		(width 0.381)
		(layer "F.Cu")
		(net "GND")
	)
	(segment
		(start 158.897574 -79.170022)
		(end 157.985968 -79.170022)
		(width 0.3556)
		(layer "F.Cu")
		(net "GND")
	)
	(segment
		(start 256.080514 -301.866808)
		(end 257.185414 -301.866808)
		(width 0.381)
		(layer "F.Cu")
		(net "GND")
	)
	(segment
		(start 459.559914 -214.316564)
		(end 458.455014 -214.316564)
		(width 0.381)
		(layer "F.Cu")
		(net "GND")
	)
	(segment
		(start 345.95308 -242.016788)
		(end 345.95308 -241.481102)
		(width 0.2032)
		(layer "F.Cu")
		(net "GND")
	)
	(segment
		(start 372.377716 -262.87222)
		(end 372.377462 -262.872474)
		(width 0.254)
		(layer "F.Cu")
		(net "GND")
	)
	(segment
		(start 86.526116 -101.759512)
		(end 87.30488 -101.759512)
		(width 0.3556)
		(layer "F.Cu")
		(net "GND")
	)
	(segment
		(start 101.302312 -239.57534)
		(end 101.302312 -239.0394)
		(width 0.2032)
		(layer "F.Cu")
		(net "GND")
	)
	(segment
		(start 52.298346 -261.916672)
		(end 53.403246 -261.916672)
		(width 0.3556)
		(layer "F.Cu")
		(net "GND")
	)
	(segment
		(start 87.675466 -237.133892)
		(end 87.675466 -236.597952)
		(width 0.254)
		(layer "F.Cu")
		(net "GND")
	)
	(segment
		(start 289.250882 -295.916604)
		(end 290.355782 -295.916604)
		(width 0.381)
		(layer "F.Cu")
		(net "GND")
	)
	(segment
		(start 207.70215 -114.53495)
		(end 207.899 -114.7318)
		(width 0.3556)
		(layer "F.Cu")
		(net "GND")
	)
	(segment
		(start 110.97768 -391.556748)
		(end 110.551976 -391.556748)
		(width 0.3556)
		(layer "F.Cu")
		(net "GND")
	)
	(segment
		(start 186.649614 -303.566576)
		(end 185.544714 -303.566576)
		(width 0.381)
		(layer "F.Cu")
		(net "GND")
	)
	(segment
		(start 375.666762 -253.919482)
		(end 375.667016 -253.919736)
		(width 0.2032)
		(layer "F.Cu")
		(net "GND")
	)
	(segment
		(start 462.120996 -103.614728)
		(end 462.120996 -104.249728)
		(width 0.3556)
		(layer "F.Cu")
		(net "GND")
	)
	(segment
		(start 208.176114 -232.166668)
		(end 209.281014 -232.166668)
		(width 0.381)
		(layer "F.Cu")
		(net "GND")
	)
	(segment
		(start 355.930962 -276.708362)
		(end 355.931216 -276.708616)
		(width 0.2032)
		(layer "F.Cu")
		(net "GND")
	)
	(segment
		(start 344.54338 -220.041978)
		(end 344.543634 -220.041724)
		(width 0.254)
		(layer "F.Cu")
		(net "GND")
	)
	(segment
		(start 444.472314 -296.766742)
		(end 445.577214 -296.766742)
		(width 0.381)
		(layer "F.Cu")
		(net "GND")
	)
	(segment
		(start 382.245362 -258.802886)
		(end 382.245616 -258.80314)
		(width 0.2032)
		(layer "F.Cu")
		(net "GND")
	)
	(segment
		(start 385.424934 -246.900446)
		(end 385.424934 -246.364506)
		(width 0.254)
		(layer "F.Cu")
		(net "GND")
	)
	(segment
		(start 169.04843 -422.874948)
		(end 168.43883 -422.874948)
		(width 0.3556)
		(layer "F.Cu")
		(net "GND")
	)
	(segment
		(start 419.502082 -245.76659)
		(end 418.397182 -245.76659)
		(width 0.381)
		(layer "F.Cu")
		(net "GND")
	)
	(segment
		(start 37.330634 -110.587282)
		(end 37.940234 -110.587282)
		(width 0.3556)
		(layer "F.Cu")
		(net "GND")
	)
	(segment
		(start 359.58018 -223.297496)
		(end 359.58018 -222.76181)
		(width 0.254)
		(layer "F.Cu")
		(net "GND")
	)
	(segment
		(start 88.145366 -216.78646)
		(end 88.145366 -216.251028)
		(width 0.2032)
		(layer "F.Cu")
		(net "GND")
	)
	(segment
		(start 45.859446 -279.766776)
		(end 46.964346 -279.766776)
		(width 0.381)
		(layer "F.Cu")
		(net "GND")
	)
	(segment
		(start 353.094544 -338.86013)
		(end 352.617786 -338.86013)
		(width 0.381)
		(layer "F.Cu")
		(net "GND")
	)
	(segment
		(start 14.579346 -301.866808)
		(end 15.684246 -301.866808)
		(width 0.381)
		(layer "F.Cu")
		(net "GND")
	)
	(segment
		(start 52.298346 -281.466798)
		(end 53.403246 -281.466798)
		(width 0.381)
		(layer "F.Cu")
		(net "GND")
	)
	(segment
		(start 464.764882 -289.966654)
		(end 463.659982 -289.966654)
		(width 0.381)
		(layer "F.Cu")
		(net "GND")
	)
	(segment
		(start 211.619846 -223.666558)
		(end 212.724746 -223.666558)
		(width 0.381)
		(layer "F.Cu")
		(net "GND")
	)
	(segment
		(start 172.795946 -273.816572)
		(end 173.900846 -273.816572)
		(width 0.381)
		(layer "F.Cu")
		(net "GND")
	)
	(segment
		(start 114.569494 -276.708362)
		(end 114.569748 -276.708616)
		(width 0.254)
		(layer "F.Cu")
		(net "GND")
	)
	(segment
		(start 308.887114 -199.01662)
		(end 309.992014 -199.01662)
		(width 0.381)
		(layer "F.Cu")
		(net "GND")
	)
	(segment
		(start 91.434666 -243.108988)
		(end 91.434666 -243.644928)
		(width 0.2032)
		(layer "F.Cu")
		(net "GND")
	)
	(segment
		(start 113.519966 -231.436164)
		(end 113.519966 -230.900478)
		(width 0.2032)
		(layer "F.Cu")
		(net "GND")
	)
	(segment
		(start 341.37727 -53.149246)
		(end 341.37727 -52.209446)
		(width 0.2032)
		(layer "F.Cu")
		(net "GND")
	)
	(segment
		(start 29.666946 -217.716608)
		(end 30.771846 -217.716608)
		(width 0.381)
		(layer "F.Cu")
		(net "GND")
	)
	(segment
		(start 418.397182 -269.566644)
		(end 417.292282 -269.566644)
		(width 0.381)
		(layer "F.Cu")
		(net "GND")
	)
	(segment
		(start 294.904414 -295.06672)
		(end 293.799514 -295.06672)
		(width 0.381)
		(layer "F.Cu")
		(net "GND")
	)
	(segment
		(start 260.180582 -258.516628)
		(end 259.075682 -258.516628)
		(width 0.381)
		(layer "F.Cu")
		(net "GND")
	)
	(segment
		(start 358.170734 -242.017042)
		(end 358.170734 -241.481102)
		(width 0.254)
		(layer "F.Cu")
		(net "GND")
	)
	(segment
		(start 360.990134 -238.761524)
		(end 360.98988 -238.76127)
		(width 0.254)
		(layer "F.Cu")
		(net "GND")
	)
	(segment
		(start 371.327934 -240.389156)
		(end 371.32768 -240.388902)
		(width 0.2032)
		(layer "F.Cu")
		(net "GND")
	)
	(segment
		(start 18.728182 -428.424086)
		(end 18.753582 -428.449486)
		(width 0.3556)
		(layer "F.Cu")
		(net "GND")
	)
	(segment
		(start 384.015234 -224.925382)
		(end 384.015234 -224.389442)
		(width 0.254)
		(layer "F.Cu")
		(net "GND")
	)
	(segment
		(start 144.720056 -76.481432)
		(end 144.720056 -77.532738)
		(width 0.3556)
		(layer "F.Cu")
		(net "GND")
	)
	(segment
		(start 134.195566 -226.017328)
		(end 134.195566 -226.553268)
		(width 0.254)
		(layer "F.Cu")
		(net "GND")
	)
	(segment
		(start 56.398414 -310.366664)
		(end 57.503314 -310.366664)
		(width 0.381)
		(layer "F.Cu")
		(net "GND")
	)
	(segment
		(start 339.954362 -274.54479)
		(end 339.954362 -275.08073)
		(width 0.2032)
		(layer "F.Cu")
		(net "GND")
	)
	(segment
		(start 281.707082 -222.816674)
		(end 282.811982 -222.816674)
		(width 0.381)
		(layer "F.Cu")
		(net "GND")
	)
	(segment
		(start 361.45978 -242.295172)
		(end 361.460034 -242.294918)
		(width 0.254)
		(layer "F.Cu")
		(net "GND")
	)
	(segment
		(start 370.498116 -259.093462)
		(end 370.497862 -259.616956)
		(width 0.254)
		(layer "F.Cu")
		(net "GND")
	)
	(segment
		(start 456.119992 -49.476406)
		(end 457.0349 -49.476406)
		(width 0.508)
		(layer "F.Cu")
		(net "GND")
	)
	(segment
		(start 428.279814 -229.616762)
		(end 429.384714 -229.616762)
		(width 0.381)
		(layer "F.Cu")
		(net "GND")
	)
	(segment
		(start 429.384714 -244.916706)
		(end 430.489614 -244.916706)
		(width 0.381)
		(layer "F.Cu")
		(net "GND")
	)
	(segment
		(start 424.836082 -207.51673)
		(end 425.940982 -207.51673)
		(width 0.381)
		(layer "F.Cu")
		(net "GND")
	)
	(segment
		(start 130.906012 -242.016788)
		(end 130.906012 -241.481102)
		(width 0.2032)
		(layer "F.Cu")
		(net "GND")
	)
	(segment
		(start 285.664402 -362.856018)
		(end 285.664402 -362.390182)
		(width 0.2032)
		(layer "F.Cu")
		(net "GND")
	)
	(segment
		(start 327.980548 -58.43524)
		(end 328.395584 -58.020204)
		(width 0.2032)
		(layer "F.Cu")
		(net "GND")
	)
	(segment
		(start 334.315562 -256.639314)
		(end 334.785462 -256.361438)
		(width 0.254)
		(layer "F.Cu")
		(net "GND")
	)
	(segment
		(start 410.853382 -266.1666)
		(end 411.958282 -266.1666)
		(width 0.381)
		(layer "F.Cu")
		(net "GND")
	)
	(segment
		(start 23.228046 -210.916774)
		(end 24.332946 -210.916774)
		(width 0.381)
		(layer "F.Cu")
		(net "GND")
	)
	(segment
		(start 441.028582 -286.56661)
		(end 442.133482 -286.56661)
		(width 0.381)
		(layer "F.Cu")
		(net "GND")
	)
	(segment
		(start 170.457114 -316.316614)
		(end 171.562014 -316.316614)
		(width 0.381)
		(layer "F.Cu")
		(net "GND")
	)
	(segment
		(start 94.364048 -254.197612)
		(end 94.833694 -253.919736)
		(width 0.2032)
		(layer "F.Cu")
		(net "GND")
	)
	(segment
		(start 308.887114 -273.816572)
		(end 310.207914 -273.816572)
		(width 0.381)
		(layer "F.Cu")
		(net "GND")
	)
	(segment
		(start 39.420546 -311.216802)
		(end 38.315646 -311.216802)
		(width 0.381)
		(layer "F.Cu")
		(net "GND")
	)
	(segment
		(start 262.519414 -240.666778)
		(end 263.624314 -240.666778)
		(width 0.381)
		(layer "F.Cu")
		(net "GND")
	)
	(segment
		(start 267.724382 -310.366664)
		(end 268.829282 -310.366664)
		(width 0.381)
		(layer "F.Cu")
		(net "GND")
	)
	(segment
		(start 421.840914 -279.766776)
		(end 420.736014 -279.766776)
		(width 0.381)
		(layer "F.Cu")
		(net "GND")
	)
	(segment
		(start 357.70058 -214.622888)
		(end 357.700326 -214.622634)
		(width 0.1778)
		(layer "F.Cu")
		(net "GND")
	)
	(segment
		(start 19.784314 -210.066636)
		(end 18.679414 -210.066636)
		(width 0.381)
		(layer "F.Cu")
		(net "GND")
	)
	(segment
		(start 7.035546 -263.616694)
		(end 8.140446 -263.616694)
		(width 0.381)
		(layer "F.Cu")
		(net "GND")
	)
	(segment
		(start 444.472314 -210.916774)
		(end 443.367414 -210.916774)
		(width 0.381)
		(layer "F.Cu")
		(net "GND")
	)
	(segment
		(start 420.736014 -236.416596)
		(end 421.840914 -236.416596)
		(width 0.381)
		(layer "F.Cu")
		(net "GND")
	)
	(segment
		(start 193.47688 -71.948548)
		(end 193.76517 -72.236838)
		(width 0.3556)
		(layer "F.Cu")
		(net "GND")
	)
	(segment
		(start 123.027694 -285.939484)
		(end 123.027694 -286.475424)
		(width 0.2032)
		(layer "F.Cu")
		(net "GND")
	)
	(segment
		(start 35.976814 -297.616626)
		(end 34.871914 -297.616626)
		(width 0.381)
		(layer "F.Cu")
		(net "GND")
	)
	(segment
		(start 343.821258 -46.100492)
		(end 343.81948 -46.100746)
		(width 0.254)
		(layer "F.Cu")
		(net "GND")
	)
	(segment
		(start 160.43783 -118.836948)
		(end 159.82188 -118.836948)
		(width 0.3556)
		(layer "F.Cu")
		(net "GND")
	)
	(segment
		(start 342.773762 -276.172676)
		(end 342.773762 -276.708362)
		(width 0.2032)
		(layer "F.Cu")
		(net "GND")
	)
	(segment
		(start 208.054956 -29.876242)
		(end 208.054956 -29.266642)
		(width 0.3556)
		(layer "F.Cu")
		(net "GND")
	)
	(segment
		(start 360.520234 -229.808532)
		(end 360.520234 -229.272846)
		(width 0.2032)
		(layer "F.Cu")
		(net "GND")
	)
	(segment
		(start 275.268182 -222.816674)
		(end 276.373082 -222.816674)
		(width 0.381)
		(layer "F.Cu")
		(net "GND")
	)
	(segment
		(start 198.12508 -111.324898)
		(end 198.77913 -111.978948)
		(width 0.3556)
		(layer "F.Cu")
		(net "GND")
	)
	(segment
		(start 311.882282 -288.266632)
		(end 312.987182 -288.266632)
		(width 0.381)
		(layer "F.Cu")
		(net "GND")
	)
	(segment
		(start 30.771846 -317.166752)
		(end 31.876746 -317.166752)
		(width 0.381)
		(layer "F.Cu")
		(net "GND")
	)
	(segment
		(start 130.436112 -219.506292)
		(end 130.436366 -219.506038)
		(width 0.254)
		(layer "F.Cu")
		(net "GND")
	)
	(segment
		(start 413.120332 -29.877258)
		(end 413.120332 -30.893258)
		(width 0.3556)
		(layer "F.Cu")
		(net "GND")
	)
	(segment
		(start 348.772734 -228.99497)
		(end 348.77248 -228.994716)
		(width 0.2032)
		(layer "F.Cu")
		(net "GND")
	)
	(segment
		(start 91.074494 -253.383796)
		(end 91.074494 -253.919482)
		(width 0.2032)
		(layer "F.Cu")
		(net "GND")
	)
	(segment
		(start 420.736014 -261.916672)
		(end 421.840914 -261.916672)
		(width 0.381)
		(layer "F.Cu")
		(net "GND")
	)
	(segment
		(start 332.796134 -224.111566)
		(end 332.796134 -223.575626)
		(width 0.254)
		(layer "F.Cu")
		(net "GND")
	)
	(segment
		(start 256.080514 -290.816792)
		(end 257.185414 -290.816792)
		(width 0.381)
		(layer "F.Cu")
		(net "GND")
	)
	(segment
		(start 208.176114 -271.266666)
		(end 209.281014 -271.266666)
		(width 0.381)
		(layer "F.Cu")
		(net "GND")
	)
	(segment
		(start 215.719914 -264.466578)
		(end 216.824814 -264.466578)
		(width 0.381)
		(layer "F.Cu")
		(net "GND")
	)
	(segment
		(start 166.357046 -292.516814)
		(end 167.461946 -292.516814)
		(width 0.381)
		(layer "F.Cu")
		(net "GND")
	)
	(segment
		(start 275.268182 -247.466612)
		(end 274.163282 -247.466612)
		(width 0.381)
		(layer "F.Cu")
		(net "GND")
	)
	(segment
		(start 305.443382 -308.666642)
		(end 306.548282 -308.666642)
		(width 0.381)
		(layer "F.Cu")
		(net "GND")
	)
	(segment
		(start 48.854614 -245.76659)
		(end 49.959514 -245.76659)
		(width 0.381)
		(layer "F.Cu")
		(net "GND")
	)
	(segment
		(start 98.123248 -260.708902)
		(end 98.123248 -261.244588)
		(width 0.2032)
		(layer "F.Cu")
		(net "GND")
	)
	(segment
		(start 271.168114 -267.016738)
		(end 270.063214 -267.016738)
		(width 0.381)
		(layer "F.Cu")
		(net "GND")
	)
	(segment
		(start 132.425694 -279.428194)
		(end 132.425694 -279.964134)
		(width 0.254)
		(layer "F.Cu")
		(net "GND")
	)
	(segment
		(start 343.713562 -282.683966)
		(end 343.713562 -283.219906)
		(width 0.2032)
		(layer "F.Cu")
		(net "GND")
	)
	(segment
		(start 87.205312 -217.87866)
		(end 87.205058 -217.878406)
		(width 0.2032)
		(layer "F.Cu")
		(net "GND")
	)
	(segment
		(start 55.066946 -8.320024)
		(end 55.066946 -7.215124)
		(width 0.3556)
		(layer "F.Cu")
		(net "GND")
	)
	(segment
		(start 271.168114 -248.31675)
		(end 270.063214 -248.31675)
		(width 0.381)
		(layer "F.Cu")
		(net "GND")
	)
	(segment
		(start 305.443382 -284.866588)
		(end 306.548282 -284.866588)
		(width 0.381)
		(layer "F.Cu")
		(net "GND")
	)
	(segment
		(start 383.07518 -237.411768)
		(end 383.075434 -237.411514)
		(width 0.254)
		(layer "F.Cu")
		(net "GND")
	)
	(segment
		(start 90.604848 -262.336534)
		(end 90.604848 -262.872474)
		(width 0.2032)
		(layer "F.Cu")
		(net "GND")
	)
	(segment
		(start 207.071214 -264.466578)
		(end 208.176114 -264.466578)
		(width 0.381)
		(layer "F.Cu")
		(net "GND")
	)
	(segment
		(start 377.43638 -226.553268)
		(end 377.43638 -226.017582)
		(width 0.254)
		(layer "F.Cu")
		(net "GND")
	)
	(segment
		(start 343.549478 -45.630592)
		(end 343.821258 -46.100492)
		(width 0.254)
		(layer "F.Cu")
		(net "GND")
	)
	(segment
		(start 43.520614 -238.116618)
		(end 42.415714 -238.116618)
		(width 0.381)
		(layer "F.Cu")
		(net "GND")
	)
	(segment
		(start 131.846066 -240.389156)
		(end 131.846066 -239.853216)
		(width 0.2032)
		(layer "F.Cu")
		(net "GND")
	)
	(segment
		(start 296.578782 -210.066636)
		(end 297.899582 -210.066636)
		(width 0.381)
		(layer "F.Cu")
		(net "GND")
	)
	(segment
		(start 89.555066 -237.133892)
		(end 89.554812 -237.133638)
		(width 0.254)
		(layer "F.Cu")
		(net "GND")
	)
	(segment
		(start 52.298346 -258.516628)
		(end 53.403246 -258.516628)
		(width 0.381)
		(layer "F.Cu")
		(net "GND")
	)
	(segment
		(start 294.904414 -208.366614)
		(end 293.799514 -208.366614)
		(width 0.381)
		(layer "F.Cu")
		(net "GND")
	)
	(segment
		(start 101.882448 -286.7533)
		(end 101.882448 -287.288986)
		(width 0.254)
		(layer "F.Cu")
		(net "GND")
	)
	(segment
		(start 297.899582 -215.166702)
		(end 299.004482 -215.166702)
		(width 0.381)
		(layer "F.Cu")
		(net "GND")
	)
	(segment
		(start 51.064414 -215.166702)
		(end 49.959514 -215.166702)
		(width 0.381)
		(layer "F.Cu")
		(net "GND")
	)
	(segment
		(start 289.250882 -301.01667)
		(end 290.355782 -301.01667)
		(width 0.381)
		(layer "F.Cu")
		(net "GND")
	)
	(segment
		(start 43.520614 -299.316648)
		(end 42.415714 -299.316648)
		(width 0.381)
		(layer "F.Cu")
		(net "GND")
	)
	(segment
		(start 464.764882 -316.316614)
		(end 463.659982 -316.316614)
		(width 0.381)
		(layer "F.Cu")
		(net "GND")
	)
	(segment
		(start 26.223214 -238.116618)
		(end 27.328114 -238.116618)
		(width 0.381)
		(layer "F.Cu")
		(net "GND")
	)
	(segment
		(start 339.901276 -39.295324)
		(end 338.90077 -39.295324)
		(width 0.2032)
		(layer "F.Cu")
		(net "GND")
	)
	(segment
		(start 342.66378 -239.57534)
		(end 342.66378 -239.0394)
		(width 0.2032)
		(layer "F.Cu")
		(net "GND")
	)
	(segment
		(start 385.064762 -283.219144)
		(end 385.065016 -283.219398)
		(width 0.254)
		(layer "F.Cu")
		(net "GND")
	)
	(segment
		(start 428.279814 -206.666592)
		(end 429.384714 -206.666592)
		(width 0.381)
		(layer "F.Cu")
		(net "GND")
	)
	(segment
		(start 452.016114 -225.36658)
		(end 450.911214 -225.36658)
		(width 0.381)
		(layer "F.Cu")
		(net "GND")
	)
	(segment
		(start 378.016516 -287.288986)
		(end 378.016262 -287.28924)
		(width 0.254)
		(layer "F.Cu")
		(net "GND")
	)
	(segment
		(start 352.171762 -282.683966)
		(end 352.171762 -283.219906)
		(width 0.2032)
		(layer "F.Cu")
		(net "GND")
	)
	(segment
		(start 263.624314 -313.766708)
		(end 264.729214 -313.766708)
		(width 0.381)
		(layer "F.Cu")
		(net "GND")
	)
	(segment
		(start 350.18218 -222.76181)
		(end 350.182434 -222.761556)
		(width 0.254)
		(layer "F.Cu")
		(net "GND")
	)
	(segment
		(start 377.43638 -226.017582)
		(end 377.436634 -226.017328)
		(width 0.254)
		(layer "F.Cu")
		(net "GND")
	)
	(segment
		(start 435.823614 -306.116736)
		(end 436.928514 -306.116736)
		(width 0.381)
		(layer "F.Cu")
		(net "GND")
	)
	(segment
		(start 368.03838 -226.017582)
		(end 368.038634 -226.017328)
		(width 0.254)
		(layer "F.Cu")
		(net "GND")
	)
	(segment
		(start 124.907294 -277.800562)
		(end 124.907294 -278.336248)
		(width 0.254)
		(layer "F.Cu")
		(net "GND")
	)
	(segment
		(start 38.315646 -248.31675)
		(end 37.210746 -248.31675)
		(width 0.381)
		(layer "F.Cu")
		(net "GND")
	)
	(segment
		(start 110.340648 -272.103342)
		(end 110.340648 -272.639028)
		(width 0.254)
		(layer "F.Cu")
		(net "GND")
	)
	(segment
		(start 351.702116 -275.894546)
		(end 351.701862 -275.8948)
		(width 0.2032)
		(layer "F.Cu")
		(net "GND")
	)
	(segment
		(start 45.859446 -212.616796)
		(end 46.964346 -212.616796)
		(width 0.381)
		(layer "F.Cu")
		(net "GND")
	)
	(segment
		(start 375.55678 -226.553268)
		(end 375.55678 -226.017582)
		(width 0.254)
		(layer "F.Cu")
		(net "GND")
	)
	(segment
		(start 449.677282 -230.466646)
		(end 448.572382 -230.466646)
		(width 0.381)
		(layer "F.Cu")
		(net "GND")
	)
	(segment
		(start 176.896014 -316.316614)
		(end 178.000914 -316.316614)
		(width 0.381)
		(layer "F.Cu")
		(net "GND")
	)
	(segment
		(start 215.719914 -291.666676)
		(end 216.824814 -291.666676)
		(width 0.381)
		(layer "F.Cu")
		(net "GND")
	)
	(segment
		(start 200.632314 -247.466612)
		(end 201.737214 -247.466612)
		(width 0.381)
		(layer "F.Cu")
		(net "GND")
	)
	(segment
		(start 94.364048 -264.500106)
		(end 94.363794 -264.50036)
		(width 0.254)
		(layer "F.Cu")
		(net "GND")
	)
	(segment
		(start 424.836082 -228.766624)
		(end 425.940982 -228.766624)
		(width 0.381)
		(layer "F.Cu")
		(net "GND")
	)
	(segment
		(start 296.794682 -262.76681)
		(end 297.899582 -262.76681)
		(width 0.381)
		(layer "F.Cu")
		(net "GND")
	)
	(segment
		(start 105.179622 -238.695484)
		(end 105.179622 -239.292892)
		(width 0.254)
		(layer "F.Cu")
		(net "GND")
	)
	(segment
		(start 122.917966 -220.041724)
		(end 122.917966 -219.506038)
		(width 0.254)
		(layer "F.Cu")
		(net "GND")
	)
	(segment
		(start 337.845908 -15.819628)
		(end 337.845908 -14.99235)
		(width 0.3556)
		(layer "F.Cu")
		(net "GND")
	)
	(segment
		(start 297.899582 -271.266666)
		(end 299.004482 -271.266666)
		(width 0.381)
		(layer "F.Cu")
		(net "GND")
	)
	(segment
		(start 126.317248 -255.825498)
		(end 126.317248 -256.361184)
		(width 0.254)
		(layer "F.Cu")
		(net "GND")
	)
	(segment
		(start 374.726962 -289.195002)
		(end 374.726962 -289.807142)
		(width 0.2032)
		(layer "F.Cu")
		(net "GND")
	)
	(segment
		(start 370.027962 -266.405868)
		(end 370.028216 -266.941808)
		(width 0.254)
		(layer "F.Cu")
		(net "GND")
	)
	(segment
		(start 435.823614 -195.616576)
		(end 436.928514 -195.616576)
		(width 0.381)
		(layer "F.Cu")
		(net "GND")
	)
	(segment
		(start 417.834572 -182.210202)
		(end 417.834572 -181.857904)
		(width 0.2032)
		(layer "F.Cu")
		(net "GND")
	)
	(segment
		(start 363.809534 -230.622602)
		(end 363.80928 -230.622348)
		(width 0.2032)
		(layer "F.Cu")
		(net "GND")
	)
	(segment
		(start 108.31576 -408.036014)
		(end 107.583986 -408.036014)
		(width 0.3556)
		(layer "F.Cu")
		(net "GND")
	)
	(segment
		(start 266.619482 -289.966654)
		(end 267.724382 -289.966654)
		(width 0.381)
		(layer "F.Cu")
		(net "GND")
	)
	(segment
		(start 345.48699 -41.847008)
		(end 345.554554 -41.947084)
		(width 0.2032)
		(layer "F.Cu")
		(net "GND")
	)
	(segment
		(start 154.81808 -130.851148)
		(end 156.122878 -132.155946)
		(width 0.3556)
		(layer "F.Cu")
		(net "GND")
	)
	(segment
		(start 345.123516 -272.103342)
		(end 345.123516 -272.639282)
		(width 0.2032)
		(layer "F.Cu")
		(net "GND")
	)
	(segment
		(start 26.223214 -245.76659)
		(end 27.328114 -245.76659)
		(width 0.381)
		(layer "F.Cu")
		(net "GND")
	)
	(segment
		(start 290.355782 -272.966688)
		(end 291.460682 -272.966688)
		(width 0.381)
		(layer "F.Cu")
		(net "GND")
	)
	(segment
		(start 328.244962 -51.95189)
		(end 328.625708 -51.269646)
		(width 0.2032)
		(layer "F.Cu")
		(net "GND")
	)
	(segment
		(start 18.679414 -238.116618)
		(end 19.784314 -238.116618)
		(width 0.381)
		(layer "F.Cu")
		(net "GND")
	)
	(segment
		(start 118.798594 -281.87015)
		(end 118.798594 -282.405836)
		(width 0.254)
		(layer "F.Cu")
		(net "GND")
	)
	(segment
		(start 375.463562 -103.176578)
		(end 375.718578 -102.921562)
		(width 0.3556)
		(layer "F.Cu")
		(net "GND")
	)
	(segment
		(start 271.168114 -212.616796)
		(end 270.063214 -212.616796)
		(width 0.381)
		(layer "F.Cu")
		(net "GND")
	)
	(segment
		(start 8.140446 -250.016772)
		(end 9.245346 -250.016772)
		(width 0.381)
		(layer "F.Cu")
		(net "GND")
	)
	(segment
		(start 105.171494 -287.567116)
		(end 105.171748 -288.103056)
		(width 0.254)
		(layer "F.Cu")
		(net "GND")
	)
	(segment
		(start 294.904414 -258.516628)
		(end 293.799514 -258.516628)
		(width 0.381)
		(layer "F.Cu")
		(net "GND")
	)
	(segment
		(start 113.519966 -229.808532)
		(end 113.519966 -229.272846)
		(width 0.2032)
		(layer "F.Cu")
		(net "GND")
	)
	(segment
		(start 15.684246 -197.316598)
		(end 16.789146 -197.316598)
		(width 0.381)
		(layer "F.Cu")
		(net "GND")
	)
	(segment
		(start 19.784314 -314.616592)
		(end 20.889214 -314.616592)
		(width 0.381)
		(layer "F.Cu")
		(net "GND")
	)
	(segment
		(start 12.240514 -312.91657)
		(end 13.345414 -312.91657)
		(width 0.381)
		(layer "F.Cu")
		(net "GND")
	)
	(segment
		(start 197.637146 -309.51678)
		(end 196.532246 -309.51678)
		(width 0.381)
		(layer "F.Cu")
		(net "GND")
	)
	(segment
		(start 308.887114 -214.316564)
		(end 309.992014 -214.316564)
		(width 0.381)
		(layer "F.Cu")
		(net "GND")
	)
	(segment
		(start 338.90458 -229.808786)
		(end 338.904834 -229.808532)
		(width 0.2032)
		(layer "F.Cu")
		(net "GND")
	)
	(segment
		(start 123.96978 -110.200948)
		(end 123.96978 -109.070648)
		(width 0.3556)
		(layer "F.Cu")
		(net "GND")
	)
	(segment
		(start 369.373658 -413.50438)
		(end 369.368578 -413.50946)
		(width 0.3556)
		(layer "F.Cu")
		(net "GND")
	)
	(segment
		(start 172.795946 -317.166752)
		(end 173.900846 -317.166752)
		(width 0.381)
		(layer "F.Cu")
		(net "GND")
	)
	(segment
		(start 386.474716 -278.614378)
		(end 386.944362 -278.336502)
		(width 0.254)
		(layer "F.Cu")
		(net "GND")
	)
	(segment
		(start 106.001312 -222.76181)
		(end 106.001566 -222.761556)
		(width 0.254)
		(layer "F.Cu")
		(net "GND")
	)
	(segment
		(start 335.615534 -232.250488)
		(end 335.615534 -231.714548)
		(width 0.254)
		(layer "F.Cu")
		(net "GND")
	)
	(segment
		(start 358.170734 -224.111566)
		(end 358.170734 -223.575626)
		(width 0.2032)
		(layer "F.Cu")
		(net "GND")
	)
	(segment
		(start 191.983614 -314.616592)
		(end 193.088514 -314.616592)
		(width 0.381)
		(layer "F.Cu")
		(net "GND")
	)
	(segment
		(start 131.016248 -283.497782)
		(end 131.016248 -284.033468)
		(width 0.254)
		(layer "F.Cu")
		(net "GND")
	)
	(segment
		(start 370.85778 -216.250774)
		(end 370.858034 -216.25052)
		(width 0.254)
		(layer "F.Cu")
		(net "GND")
	)
	(segment
		(start 328.625708 -51.269646)
		(end 328.244962 -50.951384)
		(width 0.254)
		(layer "F.Cu")
		(net "GND")
	)
	(segment
		(start 65.047114 -272.966688)
		(end 66.367914 -272.966688)
		(width 0.381)
		(layer "F.Cu")
		(net "GND")
	)
	(segment
		(start 381.19558 -228.1809)
		(end 381.195834 -228.180646)
		(width 0.2032)
		(layer "F.Cu")
		(net "GND")
	)
	(segment
		(start 181.444646 -195.616576)
		(end 182.549546 -195.616576)
		(width 0.381)
		(layer "F.Cu")
		(net "GND")
	)
	(segment
		(start 185.544714 -249.166634)
		(end 186.649614 -249.166634)
		(width 0.381)
		(layer "F.Cu")
		(net "GND")
	)
	(segment
		(start 436.928514 -295.06672)
		(end 438.033414 -295.06672)
		(width 0.381)
		(layer "F.Cu")
		(net "GND")
	)
	(segment
		(start 113.519712 -242.29568)
		(end 113.52022 -242.295172)
		(width 0.254)
		(layer "F.Cu")
		(net "GND")
	)
	(segment
		(start 92.014294 -274.54479)
		(end 92.014294 -275.08073)
		(width 0.2032)
		(layer "F.Cu")
		(net "GND")
	)
	(segment
		(start 275.268182 -241.516662)
		(end 276.373082 -241.516662)
		(width 0.381)
		(layer "F.Cu")
		(net "GND")
	)
	(segment
		(start 282.811982 -291.666676)
		(end 283.916882 -291.666676)
		(width 0.381)
		(layer "F.Cu")
		(net "GND")
	)
	(segment
		(start 98.6028 -414.371536)
		(end 97.821242 -414.371536)
		(width 0.3556)
		(layer "F.Cu")
		(net "GND")
	)
	(segment
		(start 99.532694 -268.033754)
		(end 99.532948 -268.034008)
		(width 0.2032)
		(layer "F.Cu")
		(net "GND")
	)
	(segment
		(start 267.724382 -215.166702)
		(end 268.829282 -215.166702)
		(width 0.381)
		(layer "F.Cu")
		(net "GND")
	)
	(segment
		(start 444.472314 -250.016772)
		(end 445.577214 -250.016772)
		(width 0.381)
		(layer "F.Cu")
		(net "GND")
	)
	(segment
		(start 413.019748 -364.529878)
		(end 413.019748 -364.311184)
		(width 0.2032)
		(layer "F.Cu")
		(net "GND")
	)
	(segment
		(start 215.719914 -303.566576)
		(end 216.824814 -303.566576)
		(width 0.381)
		(layer "F.Cu")
		(net "GND")
	)
	(segment
		(start 44.754546 -242.3668)
		(end 45.859446 -242.3668)
		(width 0.381)
		(layer "F.Cu")
		(net "GND")
	)
	(segment
		(start 463.659982 -282.316682)
		(end 462.555082 -282.316682)
		(width 0.381)
		(layer "F.Cu")
		(net "GND")
	)
	(segment
		(start 424.166792 -8.320024)
		(end 424.166792 -9.424924)
		(width 0.3556)
		(layer "F.Cu")
		(net "GND")
	)
	(segment
		(start 63.942214 -222.816674)
		(end 65.047114 -222.816674)
		(width 0.381)
		(layer "F.Cu")
		(net "GND")
	)
	(segment
		(start 42.415714 -228.766624)
		(end 41.310814 -228.766624)
		(width 0.381)
		(layer "F.Cu")
		(net "GND")
	)
	(segment
		(start 291.460682 -196.466714)
		(end 290.355782 -196.466714)
		(width 0.381)
		(layer "F.Cu")
		(net "GND")
	)
	(segment
		(start 39.420546 -315.46673)
		(end 38.315646 -315.46673)
		(width 0.381)
		(layer "F.Cu")
		(net "GND")
	)
	(segment
		(start 307.782214 -240.666778)
		(end 308.887114 -240.666778)
		(width 0.381)
		(layer "F.Cu")
		(net "GND")
	)
	(segment
		(start 339.84438 -242.830858)
		(end 339.84438 -242.295172)
		(width 0.2032)
		(layer "F.Cu")
		(net "GND")
	)
	(segment
		(start 57.503314 -224.516696)
		(end 56.398414 -224.516696)
		(width 0.381)
		(layer "F.Cu")
		(net "GND")
	)
	(segment
		(start 59.626246 -206.666592)
		(end 60.947046 -206.666592)
		(width 0.381)
		(layer "F.Cu")
		(net "GND")
	)
	(segment
		(start 200.632314 -194.766692)
		(end 201.737214 -194.766692)
		(width 0.381)
		(layer "F.Cu")
		(net "GND")
	)
	(segment
		(start 460.664814 -197.316598)
		(end 459.559914 -197.316598)
		(width 0.381)
		(layer "F.Cu")
		(net "GND")
	)
	(segment
		(start 301.343314 -258.516628)
		(end 302.448214 -258.516628)
		(width 0.381)
		(layer "F.Cu")
		(net "GND")
	)
	(segment
		(start 39.420546 -313.766708)
		(end 38.315646 -313.766708)
		(width 0.381)
		(layer "F.Cu")
		(net "GND")
	)
	(segment
		(start 120.678448 -283.497782)
		(end 120.678448 -284.033468)
		(width 0.254)
		(layer "F.Cu")
		(net "GND")
	)
	(segment
		(start 132.895848 -273.730974)
		(end 132.895848 -274.266914)
		(width 0.2032)
		(layer "F.Cu")
		(net "GND")
	)
	(segment
		(start 86.265766 -236.319822)
		(end 86.735666 -236.597952)
		(width 0.2032)
		(layer "F.Cu")
		(net "GND")
	)
	(segment
		(start 127.726694 -253.383796)
		(end 127.726694 -253.919482)
		(width 0.2032)
		(layer "F.Cu")
		(net "GND")
	)
	(segment
		(start 116.068094 -396.798038)
		(end 116.068094 -396.163038)
		(width 0.3556)
		(layer "F.Cu")
		(net "GND")
	)
	(segment
		(start 369.088162 -285.939484)
		(end 369.088162 -286.475424)
		(width 0.2032)
		(layer "F.Cu")
		(net "GND")
	)
	(segment
		(start 164.018214 -222.816674)
		(end 162.913314 -222.816674)
		(width 0.381)
		(layer "F.Cu")
		(net "GND")
	)
	(segment
		(start 463.659982 -213.46668)
		(end 464.764882 -213.46668)
		(width 0.381)
		(layer "F.Cu")
		(net "GND")
	)
	(segment
		(start 25.746964 -11.26998)
		(end 25.746964 -12.37488)
		(width 0.3556)
		(layer "F.Cu")
		(net "GND")
	)
	(segment
		(start 353.94138 -226.553268)
		(end 353.94138 -226.017582)
		(width 0.254)
		(layer "F.Cu")
		(net "GND")
	)
	(segment
		(start 124.437648 -263.96442)
		(end 124.437648 -264.499852)
		(width 0.2032)
		(layer "F.Cu")
		(net "GND")
	)
	(segment
		(start 379.426216 -281.591766)
		(end 379.426216 -281.59202)
		(width 0.254)
		(layer "F.Cu")
		(net "GND")
	)
	(segment
		(start 414.297114 -300.166786)
		(end 415.402014 -300.166786)
		(width 0.381)
		(layer "F.Cu")
		(net "GND")
	)
	(segment
		(start 162.913314 -202.416664)
		(end 161.808414 -202.416664)
		(width 0.381)
		(layer "F.Cu")
		(net "GND")
	)
	(segment
		(start 266.619482 -233.86669)
		(end 267.724382 -233.86669)
		(width 0.381)
		(layer "F.Cu")
		(net "GND")
	)
	(segment
		(start 128.556512 -216.250774)
		(end 128.556766 -216.25052)
		(width 0.254)
		(layer "F.Cu")
		(net "GND")
	)
	(segment
		(start 101.302566 -231.436164)
		(end 101.302566 -230.900478)
		(width 0.2032)
		(layer "F.Cu")
		(net "GND")
	)
	(segment
		(start 378.846334 -250.155964)
		(end 378.84608 -250.15571)
		(width 0.2032)
		(layer "F.Cu")
		(net "GND")
	)
	(segment
		(start 385.064762 -255.011682)
		(end 384.124962 -255.547622)
		(width 0.254)
		(layer "F.Cu")
		(net "GND")
	)
	(segment
		(start 304.338482 -261.066788)
		(end 305.443382 -261.066788)
		(width 0.381)
		(layer "F.Cu")
		(net "GND")
	)
	(segment
		(start 59.626246 -311.216802)
		(end 60.947046 -311.216802)
		(width 0.381)
		(layer "F.Cu")
		(net "GND")
	)
	(segment
		(start 359.110534 -225.739198)
		(end 359.110534 -225.203512)
		(width 0.254)
		(layer "F.Cu")
		(net "GND")
	)
	(segment
		(start 354.991162 -270.197326)
		(end 354.991416 -270.19758)
		(width 0.2032)
		(layer "F.Cu")
		(net "GND")
	)
	(segment
		(start 289.250882 -303.566576)
		(end 290.355782 -303.566576)
		(width 0.381)
		(layer "F.Cu")
		(net "GND")
	)
	(segment
		(start 248.687336 -87.543386)
		(end 250.194064 -87.543386)
		(width 0.3556)
		(layer "F.Cu")
		(net "GND")
	)
	(segment
		(start 39.420546 -246.616728)
		(end 38.315646 -246.616728)
		(width 0.381)
		(layer "F.Cu")
		(net "GND")
	)
	(segment
		(start 300.022514 -217.716608)
		(end 301.343314 -217.716608)
		(width 0.381)
		(layer "F.Cu")
		(net "GND")
	)
	(segment
		(start 22.123146 -221.96679)
		(end 23.228046 -221.96679)
		(width 0.381)
		(layer "F.Cu")
		(net "GND")
	)
	(segment
		(start 456.116182 -284.866588)
		(end 455.011282 -284.866588)
		(width 0.381)
		(layer "F.Cu")
		(net "GND")
	)
	(segment
		(start 352.062034 -233.06405)
		(end 352.062034 -232.528364)
		(width 0.2032)
		(layer "F.Cu")
		(net "GND")
	)
	(segment
		(start 468.156036 -62.067948)
		(end 468.164164 -62.05982)
		(width 0.3556)
		(layer "F.Cu")
		(net "GND")
	)
	(segment
		(start 120.568466 -233.87812)
		(end 120.568212 -233.877866)
		(width 0.254)
		(layer "F.Cu")
		(net "GND")
	)
	(segment
		(start 297.899582 -291.666676)
		(end 299.004482 -291.666676)
		(width 0.381)
		(layer "F.Cu")
		(net "GND")
	)
	(segment
		(start 133.255512 -233.064304)
		(end 133.255512 -232.528364)
		(width 0.2032)
		(layer "F.Cu")
		(net "GND")
	)
	(segment
		(start 382.245362 -281.05608)
		(end 382.245362 -281.591512)
		(width 0.254)
		(layer "F.Cu")
		(net "GND")
	)
	(segment
		(start 19.784314 -239.81664)
		(end 20.889214 -239.81664)
		(width 0.381)
		(layer "F.Cu")
		(net "GND")
	)
	(segment
		(start 99.422712 -247.178576)
		(end 99.422966 -247.178322)
		(width 0.2032)
		(layer "F.Cu")
		(net "GND")
	)
	(segment
		(start 57.503314 -297.616626)
		(end 58.608214 -297.616626)
		(width 0.381)
		(layer "F.Cu")
		(net "GND")
	)
	(segment
		(start 358.280716 -285.125414)
		(end 358.280716 -285.6611)
		(width 0.254)
		(layer "F.Cu")
		(net "GND")
	)
	(segment
		(start 263.624314 -212.616796)
		(end 264.729214 -212.616796)
		(width 0.381)
		(layer "F.Cu")
		(net "GND")
	)
	(segment
		(start 293.799514 -313.766708)
		(end 292.694614 -313.766708)
		(width 0.381)
		(layer "F.Cu")
		(net "GND")
	)
	(segment
		(start 256.080514 -251.716794)
		(end 257.185414 -251.716794)
		(width 0.381)
		(layer "F.Cu")
		(net "GND")
	)
	(segment
		(start 341.833962 -265.313922)
		(end 341.834216 -265.314176)
		(width 0.2032)
		(layer "F.Cu")
		(net "GND")
	)
	(segment
		(start 177.156364 -335.483962)
		(end 178.172364 -335.483962)
		(width 0.508)
		(layer "F.Cu")
		(net "GND")
	)
	(segment
		(start 386.83438 -224.389696)
		(end 386.834634 -224.389442)
		(width 0.2032)
		(layer "F.Cu")
		(net "GND")
	)
	(segment
		(start 134.305294 -281.05608)
		(end 134.305294 -281.591512)
		(width 0.254)
		(layer "F.Cu")
		(net "GND")
	)
	(segment
		(start 178.000914 -204.116686)
		(end 176.896014 -204.116686)
		(width 0.381)
		(layer "F.Cu")
		(net "GND")
	)
	(segment
		(start 456.116182 -261.066788)
		(end 455.011282 -261.066788)
		(width 0.381)
		(layer "F.Cu")
		(net "GND")
	)
	(segment
		(start 296.794682 -213.46668)
		(end 297.899582 -213.46668)
		(width 0.381)
		(layer "F.Cu")
		(net "GND")
	)
	(segment
		(start 96.243648 -272.639028)
		(end 96.243394 -272.639282)
		(width 0.2032)
		(layer "F.Cu")
		(net "GND")
	)
	(segment
		(start 304.122582 -291.666676)
		(end 305.443382 -291.666676)
		(width 0.381)
		(layer "F.Cu")
		(net "GND")
	)
	(segment
		(start 200.632314 -262.76681)
		(end 201.737214 -262.76681)
		(width 0.381)
		(layer "F.Cu")
		(net "GND")
	)
	(segment
		(start 22.123146 -317.166752)
		(end 23.228046 -317.166752)
		(width 0.381)
		(layer "F.Cu")
		(net "GND")
	)
	(segment
		(start 435.823614 -233.016806)
		(end 436.928514 -233.016806)
		(width 0.381)
		(layer "F.Cu")
		(net "GND")
	)
	(segment
		(start 345.51874 -54.900068)
		(end 345.554554 -54.953408)
		(width 0.1778)
		(layer "F.Cu")
		(net "GND")
	)
	(segment
		(start 281.707082 -262.76681)
		(end 282.811982 -262.76681)
		(width 0.381)
		(layer "F.Cu")
		(net "GND")
	)
	(segment
		(start 260.180582 -221.116652)
		(end 259.075682 -221.116652)
		(width 0.381)
		(layer "F.Cu")
		(net "GND")
	)
	(segment
		(start 5.644642 -98.566478)
		(end 5.644642 -100.81895)
		(width 0.3556)
		(layer "F.Cu")
		(net "GND")
	)
	(segment
		(start 380.25578 -226.553268)
		(end 380.25578 -226.017582)
		(width 0.254)
		(layer "F.Cu")
		(net "GND")
	)
	(segment
		(start 457.221082 -249.166634)
		(end 456.116182 -249.166634)
		(width 0.381)
		(layer "F.Cu")
		(net "GND")
	)
	(segment
		(start 271.168114 -317.166752)
		(end 272.273014 -317.166752)
		(width 0.381)
		(layer "F.Cu")
		(net "GND")
	)
	(segment
		(start 449.677282 -200.716642)
		(end 448.572382 -200.716642)
		(width 0.381)
		(layer "F.Cu")
		(net "GND")
	)
	(segment
		(start 102.822248 -270.475456)
		(end 102.821994 -270.47571)
		(width 0.2032)
		(layer "F.Cu")
		(net "GND")
	)
	(segment
		(start 371.32768 -250.15571)
		(end 371.32768 -249.620024)
		(width 0.2032)
		(layer "F.Cu")
		(net "GND")
	)
	(segment
		(start 88.725248 -272.103342)
		(end 88.725248 -272.639282)
		(width 0.2032)
		(layer "F.Cu")
		(net "GND")
	)
	(segment
		(start 439.923682 -286.56661)
		(end 441.028582 -286.56661)
		(width 0.381)
		(layer "F.Cu")
		(net "GND")
	)
	(segment
		(start 147.797774 -53.436012)
		(end 147.188174 -53.436012)
		(width 0.3556)
		(layer "F.Cu")
		(net "GND")
	)
	(segment
		(start 355.82098 -216.250774)
		(end 355.821234 -216.25052)
		(width 0.254)
		(layer "F.Cu")
		(net "GND")
	)
	(segment
		(start 95.125286 -428.501302)
		(end 95.125286 -428.176436)
		(width 0.381)
		(layer "F.Cu")
		(net "GND")
	)
	(segment
		(start 188.988446 -212.616796)
		(end 187.883546 -212.616796)
		(width 0.381)
		(layer "F.Cu")
		(net "GND")
	)
	(segment
		(start 422.717214 -273.816572)
		(end 421.840914 -273.816572)
		(width 0.381)
		(layer "F.Cu")
		(net "GND")
	)
	(segment
		(start 98.123248 -286.7533)
		(end 98.123248 -287.288986)
		(width 0.254)
		(layer "F.Cu")
		(net "GND")
	)
	(segment
		(start 341.364316 -287.288986)
		(end 341.364062 -287.28924)
		(width 0.254)
		(layer "F.Cu")
		(net "GND")
	)
	(segment
		(start 350.18218 -220.041978)
		(end 350.182434 -220.041724)
		(width 0.254)
		(layer "F.Cu")
		(net "GND")
	)
	(segment
		(start 449.677282 -289.966654)
		(end 448.572382 -289.966654)
		(width 0.381)
		(layer "F.Cu")
		(net "GND")
	)
	(segment
		(start 181.444646 -304.416714)
		(end 180.339746 -304.416714)
		(width 0.381)
		(layer "F.Cu")
		(net "GND")
	)
	(segment
		(start 30.771846 -301.866808)
		(end 31.876746 -301.866808)
		(width 0.381)
		(layer "F.Cu")
		(net "GND")
	)
	(segment
		(start 20.889214 -219.41663)
		(end 19.784314 -219.41663)
		(width 0.381)
		(layer "F.Cu")
		(net "GND")
	)
	(segment
		(start 285.645352 -365.21771)
		(end 285.645352 -364.999016)
		(width 0.2032)
		(layer "F.Cu")
		(net "GND")
	)
	(segment
		(start 22.123146 -290.816792)
		(end 23.228046 -290.816792)
		(width 0.381)
		(layer "F.Cu")
		(net "GND")
	)
	(segment
		(start 286.255714 -283.166566)
		(end 287.360614 -283.166566)
		(width 0.381)
		(layer "F.Cu")
		(net "GND")
	)
	(segment
		(start 84.812378 -269.938754)
		(end 84.812632 -269.938246)
		(width 0.2032)
		(layer "F.Cu")
		(net "GND")
	)
	(segment
		(start 378.956316 -257.45313)
		(end 378.956062 -257.98907)
		(width 0.2032)
		(layer "F.Cu")
		(net "GND")
	)
	(segment
		(start 184.439814 -202.416664)
		(end 185.544714 -202.416664)
		(width 0.381)
		(layer "F.Cu")
		(net "GND")
	)
	(segment
		(start 286.255714 -223.666558)
		(end 287.360614 -223.666558)
		(width 0.381)
		(layer "F.Cu")
		(net "GND")
	)
	(segment
		(start 278.711914 -197.316598)
		(end 277.607014 -197.316598)
		(width 0.381)
		(layer "F.Cu")
		(net "GND")
	)
	(segment
		(start 347.641418 -57.954926)
		(end 347.214698 -57.954926)
		(width 0.2032)
		(layer "F.Cu")
		(net "GND")
	)
	(segment
		(start 336.195162 -266.405868)
		(end 336.195162 -266.941808)
		(width 0.2032)
		(layer "F.Cu")
		(net "GND")
	)
	(segment
		(start 165.252146 -203.266802)
		(end 166.357046 -203.266802)
		(width 0.381)
		(layer "F.Cu")
		(net "GND")
	)
	(segment
		(start 63.942214 -245.76659)
		(end 65.047114 -245.76659)
		(width 0.381)
		(layer "F.Cu")
		(net "GND")
	)
	(segment
		(start 342.773762 -253.383796)
		(end 343.243408 -253.10592)
		(width 0.2032)
		(layer "F.Cu")
		(net "GND")
	)
	(segment
		(start 196.532246 -296.766742)
		(end 195.427346 -296.766742)
		(width 0.381)
		(layer "F.Cu")
		(net "GND")
	)
	(segment
		(start 172.795946 -250.016772)
		(end 173.900846 -250.016772)
		(width 0.381)
		(layer "F.Cu")
		(net "GND")
	)
	(segment
		(start 349.24238 -249.342148)
		(end 349.24238 -248.806208)
		(width 0.2032)
		(layer "F.Cu")
		(net "GND")
	)
	(segment
		(start 215.719914 -267.866622)
		(end 216.824814 -267.866622)
		(width 0.381)
		(layer "F.Cu")
		(net "GND")
	)
	(segment
		(start 95.663512 -222.76181)
		(end 95.663766 -222.761556)
		(width 0.254)
		(layer "F.Cu")
		(net "GND")
	)
	(segment
		(start 273.748754 -132.64769)
		(end 272.687796 -131.586732)
		(width 0.3556)
		(layer "F.Cu")
		(net "GND")
	)
	(segment
		(start 433.484782 -211.766658)
		(end 434.589682 -211.766658)
		(width 0.381)
		(layer "F.Cu")
		(net "GND")
	)
	(segment
		(start 180.339746 -199.01662)
		(end 181.444646 -199.01662)
		(width 0.381)
		(layer "F.Cu")
		(net "GND")
	)
	(segment
		(start 376.966734 -224.111566)
		(end 376.966734 -223.575626)
		(width 0.2032)
		(layer "F.Cu")
		(net "GND")
	)
	(segment
		(start 199.527414 -219.41663)
		(end 200.632314 -219.41663)
		(width 0.381)
		(layer "F.Cu")
		(net "GND")
	)
	(segment
		(start 460.664814 -258.516628)
		(end 459.559914 -258.516628)
		(width 0.381)
		(layer "F.Cu")
		(net "GND")
	)
	(segment
		(start 200.632314 -291.666676)
		(end 201.737214 -291.666676)
		(width 0.381)
		(layer "F.Cu")
		(net "GND")
	)
	(segment
		(start 336.665316 -262.87222)
		(end 336.665062 -262.872474)
		(width 0.2032)
		(layer "F.Cu")
		(net "GND")
	)
	(segment
		(start 335.725262 -259.081016)
		(end 335.255362 -258.80314)
		(width 0.254)
		(layer "F.Cu")
		(net "GND")
	)
	(segment
		(start 278.711914 -309.51678)
		(end 279.816814 -309.51678)
		(width 0.381)
		(layer "F.Cu")
		(net "GND")
	)
	(segment
		(start 460.664814 -267.016738)
		(end 459.559914 -267.016738)
		(width 0.381)
		(layer "F.Cu")
		(net "GND")
	)
	(segment
		(start 57.503314 -272.966688)
		(end 58.824114 -272.966688)
		(width 0.381)
		(layer "F.Cu")
		(net "GND")
	)
	(segment
		(start 363.809534 -224.111566)
		(end 363.809534 -223.575626)
		(width 0.2032)
		(layer "F.Cu")
		(net "GND")
	)
	(segment
		(start 20.889214 -269.566644)
		(end 19.784314 -269.566644)
		(width 0.381)
		(layer "F.Cu")
		(net "GND")
	)
	(segment
		(start 29.346906 -7.215124)
		(end 29.346906 -8.320024)
		(width 0.3556)
		(layer "F.Cu")
		(net "GND")
	)
	(segment
		(start 8.140446 -199.01662)
		(end 9.245346 -199.01662)
		(width 0.381)
		(layer "F.Cu")
		(net "GND")
	)
	(segment
		(start 177.23358 -426.92574)
		(end 176.712372 -427.446948)
		(width 0.3556)
		(layer "F.Cu")
		(net "GND")
	)
	(segment
		(start 448.572382 -308.666642)
		(end 447.467482 -308.666642)
		(width 0.381)
		(layer "F.Cu")
		(net "GND")
	)
	(segment
		(start 48.854614 -291.666676)
		(end 49.959514 -291.666676)
		(width 0.381)
		(layer "F.Cu")
		(net "GND")
	)
	(segment
		(start 215.719914 -241.516662)
		(end 216.824814 -241.516662)
		(width 0.381)
		(layer "F.Cu")
		(net "GND")
	)
	(segment
		(start 170.965622 -334.461612)
		(end 170.965622 -335.477612)
		(width 0.508)
		(layer "F.Cu")
		(net "GND")
	)
	(segment
		(start 210.514946 -272.116804)
		(end 211.619846 -272.116804)
		(width 0.381)
		(layer "F.Cu")
		(net "GND")
	)
	(segment
		(start 362.509562 -264.778236)
		(end 362.509562 -265.314176)
		(width 0.254)
		(layer "F.Cu")
		(net "GND")
	)
	(segment
		(start 377.076716 -273.730974)
		(end 377.076462 -274.266914)
		(width 0.2032)
		(layer "F.Cu")
		(net "GND")
	)
	(segment
		(start 183.364632 -425.831)
		(end 184.023 -425.831)
		(width 0.3556)
		(layer "F.Cu")
		(net "GND")
	)
	(segment
		(start 334.37703 -338.951316)
		(end 334.03794 -338.951316)
		(width 0.2032)
		(layer "F.Cu")
		(net "GND")
	)
	(segment
		(start 131.016248 -275.35886)
		(end 131.015994 -275.8948)
		(width 0.2032)
		(layer "F.Cu")
		(net "GND")
	)
	(segment
		(start 173.900846 -203.266802)
		(end 172.795946 -203.266802)
		(width 0.381)
		(layer "F.Cu")
		(net "GND")
	)
	(segment
		(start 439.923682 -200.716642)
		(end 441.028582 -200.716642)
		(width 0.381)
		(layer "F.Cu")
		(net "GND")
	)
	(segment
		(start 100.832666 -220.855794)
		(end 100.832666 -220.319854)
		(width 0.2032)
		(layer "F.Cu")
		(net "GND")
	)
	(segment
		(start 308.887114 -246.616728)
		(end 309.992014 -246.616728)
		(width 0.381)
		(layer "F.Cu")
		(net "GND")
	)
	(segment
		(start 129.136648 -254.197612)
		(end 129.136648 -254.733298)
		(width 0.254)
		(layer "F.Cu")
		(net "GND")
	)
	(segment
		(start 281.707082 -295.916604)
		(end 282.811982 -295.916604)
		(width 0.381)
		(layer "F.Cu")
		(net "GND")
	)
	(segment
		(start 275.66874 -420.31158)
		(end 275.436076 -420.544244)
		(width 0.3556)
		(layer "F.Cu")
		(net "GND")
	)
	(segment
		(start 63.942214 -277.216616)
		(end 65.047114 -277.216616)
		(width 0.381)
		(layer "F.Cu")
		(net "GND")
	)
	(segment
		(start 171.562014 -288.266632)
		(end 170.457114 -288.266632)
		(width 0.381)
		(layer "F.Cu")
		(net "GND")
	)
	(segment
		(start 14.579346 -281.466798)
		(end 15.684246 -281.466798)
		(width 0.381)
		(layer "F.Cu")
		(net "GND")
	)
	(segment
		(start 157.831028 -47.60722)
		(end 157.831028 -46.741588)
		(width 0.3556)
		(layer "F.Cu")
		(net "GND")
	)
	(segment
		(start 210.514946 -210.916774)
		(end 211.619846 -210.916774)
		(width 0.381)
		(layer "F.Cu")
		(net "GND")
	)
	(segment
		(start 313.63539 -62.060328)
		(end 312.928 -62.060328)
		(width 0.3556)
		(layer "F.Cu")
		(net "GND")
	)
	(segment
		(start 254.975614 -250.016772)
		(end 256.080514 -250.016772)
		(width 0.381)
		(layer "F.Cu")
		(net "GND")
	)
	(segment
		(start 347.472762 -268.033754)
		(end 347.473016 -268.034008)
		(width 0.2032)
		(layer "F.Cu")
		(net "GND")
	)
	(segment
		(start 463.659982 -228.766624)
		(end 464.764882 -228.766624)
		(width 0.381)
		(layer "F.Cu")
		(net "GND")
	)
	(segment
		(start 339.84438 -222.76181)
		(end 339.844634 -222.761556)
		(width 0.254)
		(layer "F.Cu")
		(net "GND")
	)
	(segment
		(start 271.168114 -240.666778)
		(end 270.063214 -240.666778)
		(width 0.381)
		(layer "F.Cu")
		(net "GND")
	)
	(segment
		(start 191.983614 -301.01667)
		(end 193.088514 -301.01667)
		(width 0.381)
		(layer "F.Cu")
		(net "GND")
	)
	(segment
		(start 397.765016 -60.749942)
		(end 396.415006 -60.749942)
		(width 0.254)
		(layer "F.Cu")
		(net "GND")
	)
	(segment
		(start 49.959514 -194.766692)
		(end 51.064414 -194.766692)
		(width 0.381)
		(layer "F.Cu")
		(net "GND")
	)
	(segment
		(start 379.896116 -282.405582)
		(end 379.895862 -282.405836)
		(width 0.254)
		(layer "F.Cu")
		(net "GND")
	)
	(segment
		(start 282.811982 -245.76659)
		(end 283.916882 -245.76659)
		(width 0.381)
		(layer "F.Cu")
		(net "GND")
	)
	(segment
		(start 133.255512 -216.78646)
		(end 133.255512 -216.250774)
		(width 0.254)
		(layer "F.Cu")
		(net "GND")
	)
	(segment
		(start 349.352362 -256.639314)
		(end 349.352616 -256.639568)
		(width 0.2032)
		(layer "F.Cu")
		(net "GND")
	)
	(segment
		(start 13.67155 -107.123484)
		(end 14.486128 -107.123484)
		(width 0.3556)
		(layer "F.Cu")
		(net "GND")
	)
	(segment
		(start 89.66454 -279.14981)
		(end 89.664794 -279.150064)
		(width 0.2032)
		(layer "F.Cu")
		(net "GND")
	)
	(segment
		(start 386.83438 -241.203226)
		(end 387.45668 -241.203226)
		(width 0.254)
		(layer "F.Cu")
		(net "GND")
	)
	(segment
		(start 49.529238 -173.789086)
		(end 50.274728 -173.789086)
		(width 0.254)
		(layer "F.Cu")
		(net "GND")
	)
	(segment
		(start 395.854428 -50.249836)
		(end 395.62024 -50.015648)
		(width 0.254)
		(layer "F.Cu")
		(net "GND")
	)
	(segment
		(start 406.753314 -261.916672)
		(end 407.858214 -261.916672)
		(width 0.381)
		(layer "F.Cu")
		(net "GND")
	)
	(segment
		(start 125.847094 -257.175254)
		(end 125.847094 -256.639314)
		(width 0.2032)
		(layer "F.Cu")
		(net "GND")
	)
	(segment
		(start 436.928514 -250.016772)
		(end 438.033414 -250.016772)
		(width 0.381)
		(layer "F.Cu")
		(net "GND")
	)
	(segment
		(start 54.508146 -201.56678)
		(end 53.403246 -201.56678)
		(width 0.381)
		(layer "F.Cu")
		(net "GND")
	)
	(segment
		(start 18.679414 -261.066788)
		(end 19.784314 -261.066788)
		(width 0.381)
		(layer "F.Cu")
		(net "GND")
	)
	(segment
		(start 278.711914 -273.816572)
		(end 279.816814 -273.816572)
		(width 0.381)
		(layer "F.Cu")
		(net "GND")
	)
	(segment
		(start 406.753314 -223.666558)
		(end 407.858214 -223.666558)
		(width 0.381)
		(layer "F.Cu")
		(net "GND")
	)
	(segment
		(start 384.124962 -277.800562)
		(end 384.124962 -278.336502)
		(width 0.254)
		(layer "F.Cu")
		(net "GND")
	)
	(segment
		(start 345.013534 -224.111566)
		(end 345.013534 -223.575626)
		(width 0.2032)
		(layer "F.Cu")
		(net "GND")
	)
	(segment
		(start 372.377716 -283.497782)
		(end 372.377716 -284.033468)
		(width 0.254)
		(layer "F.Cu")
		(net "GND")
	)
	(segment
		(start 12.240514 -277.216616)
		(end 13.345414 -277.216616)
		(width 0.381)
		(layer "F.Cu")
		(net "GND")
	)
	(segment
		(start 419.502082 -289.966654)
		(end 418.397182 -289.966654)
		(width 0.381)
		(layer "F.Cu")
		(net "GND")
	)
	(segment
		(start 33.767014 -230.466646)
		(end 34.871914 -230.466646)
		(width 0.381)
		(layer "F.Cu")
		(net "GND")
	)
	(segment
		(start 260.180582 -230.466646)
		(end 259.075682 -230.466646)
		(width 0.381)
		(layer "F.Cu")
		(net "GND")
	)
	(segment
		(start 418.397182 -226.216718)
		(end 417.292282 -226.216718)
		(width 0.381)
		(layer "F.Cu")
		(net "GND")
	)
	(segment
		(start 306.2224 -26.3652)
		(end 307.05679 -26.3652)
		(width 0.3556)
		(layer "F.Cu")
		(net "GND")
	)
	(segment
		(start 208.176114 -275.516594)
		(end 209.281014 -275.516594)
		(width 0.381)
		(layer "F.Cu")
		(net "GND")
	)
	(segment
		(start 132.895848 -254.197612)
		(end 132.895848 -254.733552)
		(width 0.2032)
		(layer "F.Cu")
		(net "GND")
	)
	(segment
		(start 334.205834 -220.041978)
		(end 334.675734 -220.319854)
		(width 0.254)
		(layer "F.Cu")
		(net "GND")
	)
	(segment
		(start 17.737582 -428.424086)
		(end 18.728182 -428.424086)
		(width 0.3556)
		(layer "F.Cu")
		(net "GND")
	)
	(segment
		(start 347.472762 -269.66164)
		(end 347.473016 -269.661894)
		(width 0.2032)
		(layer "F.Cu")
		(net "GND")
	)
	(segment
		(start 441.028582 -280.61666)
		(end 442.133482 -280.61666)
		(width 0.381)
		(layer "F.Cu")
		(net "GND")
	)
	(segment
		(start 158.813246 -273.816572)
		(end 157.708346 -273.816572)
		(width 0.381)
		(layer "F.Cu")
		(net "GND")
	)
	(segment
		(start 413.192214 -223.666558)
		(end 414.297114 -223.666558)
		(width 0.381)
		(layer "F.Cu")
		(net "GND")
	)
	(segment
		(start 105.061512 -216.78646)
		(end 105.061512 -216.250774)
		(width 0.254)
		(layer "F.Cu")
		(net "GND")
	)
	(segment
		(start 376.96648 -248.527824)
		(end 376.96648 -247.992138)
		(width 0.2032)
		(layer "F.Cu")
		(net "GND")
	)
	(segment
		(start 194.193414 -222.816674)
		(end 193.088514 -222.816674)
		(width 0.381)
		(layer "F.Cu")
		(net "GND")
	)
	(segment
		(start 423.804842 -394.603478)
		(end 423.195242 -394.603478)
		(width 0.381)
		(layer "F.Cu")
		(net "GND")
	)
	(segment
		(start 328.187812 -42.89044)
		(end 328.244962 -42.94759)
		(width 0.2032)
		(layer "F.Cu")
		(net "GND")
	)
	(segment
		(start 353.252532 -338.702142)
		(end 353.094544 -338.86013)
		(width 0.381)
		(layer "F.Cu")
		(net "GND")
	)
	(segment
		(start 102.822248 -286.7533)
		(end 102.822248 -287.288986)
		(width 0.254)
		(layer "F.Cu")
		(net "GND")
	)
	(segment
		(start 343.13368 -245.272306)
		(end 343.13368 -244.73662)
		(width 0.2032)
		(layer "F.Cu")
		(net "GND")
	)
	(segment
		(start 449.677282 -239.81664)
		(end 448.572382 -239.81664)
		(width 0.381)
		(layer "F.Cu")
		(net "GND")
	)
	(segment
		(start 120.76049 -428.107348)
		(end 121.37009 -428.107348)
		(width 0.3556)
		(layer "F.Cu")
		(net "GND")
	)
	(segment
		(start 121.977912 -228.1809)
		(end 121.977912 -227.64496)
		(width 0.2032)
		(layer "F.Cu")
		(net "GND")
	)
	(segment
		(start 433.484782 -288.266632)
		(end 434.589682 -288.266632)
		(width 0.381)
		(layer "F.Cu")
		(net "GND")
	)
	(segment
		(start 421.840914 -265.316716)
		(end 422.945814 -265.316716)
		(width 0.381)
		(layer "F.Cu")
		(net "GND")
	)
	(segment
		(start 166.357046 -233.016806)
		(end 167.461946 -233.016806)
		(width 0.381)
		(layer "F.Cu")
		(net "GND")
	)
	(segment
		(start 199.527414 -216.866724)
		(end 200.632314 -216.866724)
		(width 0.381)
		(layer "F.Cu")
		(net "GND")
	)
	(segment
		(start 414.297114 -246.616728)
		(end 415.402014 -246.616728)
		(width 0.381)
		(layer "F.Cu")
		(net "GND")
	)
	(segment
		(start 110.197138 -333.763112)
		(end 110.197138 -333.330804)
		(width 0.2032)
		(layer "F.Cu")
		(net "GND")
	)
	(segment
		(start 46.485556 -394.429996)
		(end 46.48581 -394.43025)
		(width 0.4572)
		(layer "F.Cu")
		(net "GND")
	)
	(segment
		(start 279.816814 -301.866808)
		(end 278.711914 -301.866808)
		(width 0.381)
		(layer "F.Cu")
		(net "GND")
	)
	(segment
		(start 11.135614 -266.1666)
		(end 12.240514 -266.1666)
		(width 0.381)
		(layer "F.Cu")
		(net "GND")
	)
	(segment
		(start 125.847094 -253.919482)
		(end 125.847348 -253.919736)
		(width 0.2032)
		(layer "F.Cu")
		(net "GND")
	)
	(segment
		(start 211.619846 -273.816572)
		(end 212.724746 -273.816572)
		(width 0.381)
		(layer "F.Cu")
		(net "GND")
	)
	(segment
		(start 372.377716 -278.614378)
		(end 372.377716 -279.150064)
		(width 0.254)
		(layer "F.Cu")
		(net "GND")
	)
	(segment
		(start 312.987182 -239.81664)
		(end 314.092082 -239.81664)
		(width 0.381)
		(layer "F.Cu")
		(net "GND")
	)
	(segment
		(start 125.737112 -236.319822)
		(end 125.737112 -235.783882)
		(width 0.2032)
		(layer "F.Cu")
		(net "GND")
	)
	(segment
		(start 261.285482 -241.516662)
		(end 260.180582 -241.516662)
		(width 0.381)
		(layer "F.Cu")
		(net "GND")
	)
	(segment
		(start 155.20162 -47.846488)
		(end 154.87904 -47.523908)
		(width 0.3556)
		(layer "F.Cu")
		(net "GND")
	)
	(segment
		(start 158.813246 -260.21665)
		(end 157.708346 -260.21665)
		(width 0.381)
		(layer "F.Cu")
		(net "GND")
	)
	(segment
		(start 429.384714 -199.01662)
		(end 430.489614 -199.01662)
		(width 0.381)
		(layer "F.Cu")
		(net "GND")
	)
	(segment
		(start 22.123146 -263.616694)
		(end 23.228046 -263.616694)
		(width 0.381)
		(layer "F.Cu")
		(net "GND")
	)
	(segment
		(start 365.328962 -281.05608)
		(end 365.328962 -281.591766)
		(width 0.254)
		(layer "F.Cu")
		(net "GND")
	)
	(segment
		(start 374.147334 -228.45903)
		(end 374.147334 -228.99497)
		(width 0.2032)
		(layer "F.Cu")
		(net "GND")
	)
	(segment
		(start 335.140808 -42.341546)
		(end 335.67878 -42.341546)
		(width 0.2032)
		(layer "F.Cu")
		(net "GND")
	)
	(segment
		(start 23.228046 -258.516628)
		(end 24.332946 -258.516628)
		(width 0.381)
		(layer "F.Cu")
		(net "GND")
	)
	(segment
		(start 342.402414 -57.45734)
		(end 341.902034 -57.605168)
		(width 0.2032)
		(layer "F.Cu")
		(net "GND")
	)
	(segment
		(start 107.051094 -282.683966)
		(end 107.051094 -283.219652)
		(width 0.254)
		(layer "F.Cu")
		(net "GND")
	)
	(segment
		(start 410.853382 -219.41663)
		(end 412.00324 -219.41663)
		(width 0.381)
		(layer "F.Cu")
		(net "GND")
	)
	(segment
		(start 113.519712 -234.69219)
		(end 113.519966 -234.691936)
		(width 0.254)
		(layer "F.Cu")
		(net "GND")
	)
	(segment
		(start 22.123146 -258.516628)
		(end 23.228046 -258.516628)
		(width 0.381)
		(layer "F.Cu")
		(net "GND")
	)
	(segment
		(start 89.554812 -235.505752)
		(end 89.554812 -234.970066)
		(width 0.2032)
		(layer "F.Cu")
		(net "GND")
	)
	(segment
		(start 114.459766 -229.808786)
		(end 114.459766 -229.272846)
		(width 0.2032)
		(layer "F.Cu")
		(net "GND")
	)
	(segment
		(start 171.619672 -358.698292)
		(end 171.133008 -358.698292)
		(width 0.3556)
		(layer "F.Cu")
		(net "GND")
	)
	(segment
		(start 42.846244 -366.62106)
		(end 43.500548 -366.62106)
		(width 0.3556)
		(layer "F.Cu")
		(net "GND")
	)
	(segment
		(start 132.425694 -272.917158)
		(end 132.425948 -273.453098)
		(width 0.2032)
		(layer "F.Cu")
		(net "GND")
	)
	(segment
		(start 14.579346 -261.916672)
		(end 15.684246 -261.916672)
		(width 0.381)
		(layer "F.Cu")
		(net "GND")
	)
	(segment
		(start 172.795946 -276.366732)
		(end 173.900846 -276.366732)
		(width 0.381)
		(layer "F.Cu")
		(net "GND")
	)
	(segment
		(start 162.913314 -262.76681)
		(end 161.808414 -262.76681)
		(width 0.381)
		(layer "F.Cu")
		(net "GND")
	)
	(segment
		(start 43.520614 -314.616592)
		(end 42.415714 -314.616592)
		(width 0.381)
		(layer "F.Cu")
		(net "GND")
	)
	(segment
		(start 362.039916 -275.35886)
		(end 362.039916 -275.8948)
		(width 0.254)
		(layer "F.Cu")
		(net "GND")
	)
	(segment
		(start 337.604862 -288.916872)
		(end 337.604608 -288.917126)
		(width 0.254)
		(layer "F.Cu")
		(net "GND")
	)
	(segment
		(start 334.205834 -231.436418)
		(end 334.675734 -231.714548)
		(width 0.2032)
		(layer "F.Cu")
		(net "GND")
	)
	(segment
		(start 171.562014 -301.01667)
		(end 170.457114 -301.01667)
		(width 0.381)
		(layer "F.Cu")
		(net "GND")
	)
	(segment
		(start 457.221082 -205.816708)
		(end 456.116182 -205.816708)
		(width 0.381)
		(layer "F.Cu")
		(net "GND")
	)
	(segment
		(start 59.842146 -315.46673)
		(end 60.947046 -315.46673)
		(width 0.381)
		(layer "F.Cu")
		(net "GND")
	)
	(segment
		(start 341.724234 -233.06405)
		(end 341.724234 -232.528364)
		(width 0.254)
		(layer "F.Cu")
		(net "GND")
	)
	(segment
		(start 162.913314 -232.166668)
		(end 161.808414 -232.166668)
		(width 0.381)
		(layer "F.Cu")
		(net "GND")
	)
	(segment
		(start 348.412562 -265.313922)
		(end 348.412816 -265.314176)
		(width 0.254)
		(layer "F.Cu")
		(net "GND")
	)
	(segment
		(start 92.844112 -228.1809)
		(end 92.844366 -228.180646)
		(width 0.2032)
		(layer "F.Cu")
		(net "GND")
	)
	(segment
		(start 211.619846 -260.21665)
		(end 212.724746 -260.21665)
		(width 0.381)
		(layer "F.Cu")
		(net "GND")
	)
	(segment
		(start 100.832412 -248.527824)
		(end 100.832412 -247.992138)
		(width 0.2032)
		(layer "F.Cu")
		(net "GND")
	)
	(segment
		(start 173.900846 -304.416714)
		(end 175.005746 -304.416714)
		(width 0.381)
		(layer "F.Cu")
		(net "GND")
	)
	(segment
		(start 96.243648 -283.497782)
		(end 96.243648 -284.033468)
		(width 0.254)
		(layer "F.Cu")
		(net "GND")
	)
	(segment
		(start 132.785866 -217.600276)
		(end 132.785866 -217.064336)
		(width 0.2032)
		(layer "F.Cu")
		(net "GND")
	)
	(segment
		(start 453.121014 -220.266768)
		(end 452.016114 -220.266768)
		(width 0.381)
		(layer "F.Cu")
		(net "GND")
	)
	(segment
		(start 138.534648 -283.497782)
		(end 138.534648 -284.033468)
		(width 0.2032)
		(layer "F.Cu")
		(net "GND")
	)
	(segment
		(start 189.262004 -13.600176)
		(end 189.262004 -13.599922)
		(width 0.3556)
		(layer "F.Cu")
		(net "GND")
	)
	(segment
		(start 29.666946 -260.21665)
		(end 30.771846 -260.21665)
		(width 0.381)
		(layer "F.Cu")
		(net "GND")
	)
	(segment
		(start 100.002848 -257.45313)
		(end 100.002848 -257.988816)
		(width 0.2032)
		(layer "F.Cu")
		(net "GND")
	)
	(segment
		(start 181.444646 -240.666778)
		(end 182.549546 -240.666778)
		(width 0.381)
		(layer "F.Cu")
		(net "GND")
	)
	(segment
		(start 349.822516 -272.103342)
		(end 349.822516 -272.639028)
		(width 0.2032)
		(layer "F.Cu")
		(net "GND")
	)
	(segment
		(start 57.503314 -262.76681)
		(end 58.608214 -262.76681)
		(width 0.381)
		(layer "F.Cu")
		(net "GND")
	)
	(segment
		(start 378.956316 -261.244588)
		(end 378.956062 -261.244842)
		(width 0.2032)
		(layer "F.Cu")
		(net "GND")
	)
	(segment
		(start 353.00158 -226.553268)
		(end 353.00158 -226.017582)
		(width 0.254)
		(layer "F.Cu")
		(net "GND")
	)
	(segment
		(start 181.444646 -210.916774)
		(end 182.549546 -210.916774)
		(width 0.381)
		(layer "F.Cu")
		(net "GND")
	)
	(segment
		(start 338.544916 -280.77795)
		(end 338.544662 -280.778204)
		(width 0.1778)
		(layer "F.Cu")
		(net "GND")
	)
	(segment
		(start 432.379882 -202.416664)
		(end 433.484782 -202.416664)
		(width 0.381)
		(layer "F.Cu")
		(net "GND")
	)
	(segment
		(start 396.646908 -8.320024)
		(end 396.646908 -7.215124)
		(width 0.3556)
		(layer "F.Cu")
		(net "GND")
	)
	(segment
		(start 92.374466 -245.27256)
		(end 92.374466 -244.73662)
		(width 0.2032)
		(layer "F.Cu")
		(net "GND")
	)
	(segment
		(start 89.664794 -273.730974)
		(end 89.664794 -274.266914)
		(width 0.2032)
		(layer "F.Cu")
		(net "GND")
	)
	(segment
		(start 130.906266 -248.528078)
		(end 130.906266 -247.992138)
		(width 0.2032)
		(layer "F.Cu")
		(net "GND")
	)
	(segment
		(start 170.457114 -233.86669)
		(end 171.562014 -233.86669)
		(width 0.381)
		(layer "F.Cu")
		(net "GND")
	)
	(segment
		(start 124.907294 -282.683966)
		(end 124.907548 -282.68422)
		(width 0.254)
		(layer "F.Cu")
		(net "GND")
	)
	(segment
		(start 439.923682 -196.466714)
		(end 441.028582 -196.466714)
		(width 0.381)
		(layer "F.Cu")
		(net "GND")
	)
	(segment
		(start 39.420546 -283.166566)
		(end 38.315646 -283.166566)
		(width 0.381)
		(layer "F.Cu")
		(net "GND")
	)
	(segment
		(start 418.397182 -301.01667)
		(end 419.502082 -301.01667)
		(width 0.381)
		(layer "F.Cu")
		(net "GND")
	)
	(segment
		(start 277.607014 -290.816792)
		(end 278.711914 -290.816792)
		(width 0.381)
		(layer "F.Cu")
		(net "GND")
	)
	(segment
		(start 327.41489 -38.945566)
		(end 327.240138 -38.2905)
		(width 0.2032)
		(layer "F.Cu")
		(net "GND")
	)
	(segment
		(start 285.150814 -212.616796)
		(end 286.255714 -212.616796)
		(width 0.381)
		(layer "F.Cu")
		(net "GND")
	)
	(segment
		(start 193.76517 -72.236838)
		(end 194.35064 -72.236838)
		(width 0.3556)
		(layer "F.Cu")
		(net "GND")
	)
	(segment
		(start 367.678716 -281.869896)
		(end 367.678716 -282.405582)
		(width 0.254)
		(layer "F.Cu")
		(net "GND")
	)
	(segment
		(start 86.526116 -95.342456)
		(end 87.226394 -95.342456)
		(width 0.3556)
		(layer "F.Cu")
		(net "GND")
	)
	(segment
		(start 378.84608 -233.877866)
		(end 378.84608 -233.34218)
		(width 0.2032)
		(layer "F.Cu")
		(net "GND")
	)
	(segment
		(start 173.900846 -296.766742)
		(end 175.005746 -296.766742)
		(width 0.381)
		(layer "F.Cu")
		(net "GND")
	)
	(segment
		(start 414.297114 -290.816792)
		(end 415.402014 -290.816792)
		(width 0.381)
		(layer "F.Cu")
		(net "GND")
	)
	(segment
		(start 175.217328 -57.399936)
		(end 176.33315 -57.399936)
		(width 0.3556)
		(layer "F.Cu")
		(net "GND")
	)
	(segment
		(start 107.051094 -269.66164)
		(end 107.051348 -269.661894)
		(width 0.254)
		(layer "F.Cu")
		(net "GND")
	)
	(segment
		(start 365.54537 -355.362256)
		(end 365.83493 -355.651816)
		(width 0.381)
		(layer "F.Cu")
		(net "GND")
	)
	(segment
		(start 154.61488 -68.290948)
		(end 154.27198 -68.290948)
		(width 0.3556)
		(layer "F.Cu")
		(net "GND")
	)
	(segment
		(start 162.913314 -301.01667)
		(end 161.808414 -301.01667)
		(width 0.381)
		(layer "F.Cu")
		(net "GND")
	)
	(segment
		(start 386.944362 -263.150604)
		(end 387.414516 -262.872474)
		(width 0.254)
		(layer "F.Cu")
		(net "GND")
	)
	(segment
		(start 379.319536 -106.492802)
		(end 378.96165 -106.850688)
		(width 0.3556)
		(layer "F.Cu")
		(net "GND")
	)
	(segment
		(start 95.193866 -230.622602)
		(end 95.193612 -230.622348)
		(width 0.2032)
		(layer "F.Cu")
		(net "GND")
	)
	(segment
		(start 297.899582 -295.916604)
		(end 299.004482 -295.916604)
		(width 0.381)
		(layer "F.Cu")
		(net "GND")
	)
	(segment
		(start 290.355782 -221.116652)
		(end 291.460682 -221.116652)
		(width 0.381)
		(layer "F.Cu")
		(net "GND")
	)
	(segment
		(start 387.550914 -247.042432)
		(end 387.818122 -247.042432)
		(width 0.2032)
		(layer "F.Cu")
		(net "GND")
	)
	(segment
		(start 415.919412 -367.104676)
		(end 415.792412 -367.231676)
		(width 0.381)
		(layer "F.Cu")
		(net "GND")
	)
	(segment
		(start 128.556512 -228.1809)
		(end 128.556512 -227.64496)
		(width 0.2032)
		(layer "F.Cu")
		(net "GND")
	)
	(segment
		(start 51.95443 -335.477612)
		(end 52.894738 -335.477612)
		(width 0.508)
		(layer "F.Cu")
		(net "GND")
	)
	(segment
		(start 351.231962 -278.336248)
		(end 351.232216 -278.336502)
		(width 0.254)
		(layer "F.Cu")
		(net "GND")
	)
	(segment
		(start 110.700566 -216.78646)
		(end 110.700566 -216.25052)
		(width 0.254)
		(layer "F.Cu")
		(net "GND")
	)
	(segment
		(start 382.605534 -219.228162)
		(end 382.605534 -218.692222)
		(width 0.2032)
		(layer "F.Cu")
		(net "GND")
	)
	(segment
		(start 52.298346 -309.51678)
		(end 53.403246 -309.51678)
		(width 0.381)
		(layer "F.Cu")
		(net "GND")
	)
	(segment
		(start 338.434934 -230.622602)
		(end 338.434934 -230.086916)
		(width 0.254)
		(layer "F.Cu")
		(net "GND")
	)
	(segment
		(start 423.513504 -130.944874)
		(end 423.513504 -131.575302)
		(width 0.381)
		(layer "F.Cu")
		(net "GND")
	)
	(segment
		(start 30.771846 -283.166566)
		(end 31.876746 -283.166566)
		(width 0.381)
		(layer "F.Cu")
		(net "GND")
	)
	(segment
		(start 43.520614 -306.96662)
		(end 42.415714 -306.96662)
		(width 0.381)
		(layer "F.Cu")
		(net "GND")
	)
	(segment
		(start 406.753314 -292.516814)
		(end 407.858214 -292.516814)
		(width 0.381)
		(layer "F.Cu")
		(net "GND")
	)
	(segment
		(start 435.823614 -250.016772)
		(end 436.928514 -250.016772)
		(width 0.381)
		(layer "F.Cu")
		(net "GND")
	)
	(segment
		(start 380.366016 -281.591766)
		(end 380.366016 -281.59202)
		(width 0.254)
		(layer "F.Cu")
		(net "GND")
	)
	(segment
		(start 23.228046 -289.11677)
		(end 24.332946 -289.11677)
		(width 0.381)
		(layer "F.Cu")
		(net "GND")
	)
	(segment
		(start 328.625708 -46.570646)
		(end 328.244962 -46.949614)
		(width 0.1778)
		(layer "F.Cu")
		(net "GND")
	)
	(segment
		(start 45.859446 -229.616762)
		(end 46.964346 -229.616762)
		(width 0.381)
		(layer "F.Cu")
		(net "GND")
	)
	(segment
		(start 354.051362 -266.405868)
		(end 354.051616 -266.406122)
		(width 0.2032)
		(layer "F.Cu")
		(net "GND")
	)
	(segment
		(start 135.245094 -279.428194)
		(end 135.245094 -279.96388)
		(width 0.254)
		(layer "F.Cu")
		(net "GND")
	)
	(segment
		(start 381.665734 -227.367084)
		(end 381.665734 -226.831144)
		(width 0.2032)
		(layer "F.Cu")
		(net "GND")
	)
	(segment
		(start 263.624314 -242.3668)
		(end 264.729214 -242.3668)
		(width 0.381)
		(layer "F.Cu")
		(net "GND")
	)
	(segment
		(start 338.904834 -234.691936)
		(end 338.904834 -234.15625)
		(width 0.254)
		(layer "F.Cu")
		(net "GND")
	)
	(segment
		(start 45.657008 -8.320024)
		(end 45.657008 -9.424924)
		(width 0.3556)
		(layer "F.Cu")
		(net "GND")
	)
	(segment
		(start 308.887114 -251.716794)
		(end 309.992014 -251.716794)
		(width 0.381)
		(layer "F.Cu")
		(net "GND")
	)
	(segment
		(start 301.133764 -14.506194)
		(end 301.844456 -14.506194)
		(width 0.3556)
		(layer "F.Cu")
		(net "GND")
	)
	(segment
		(start 448.93357 -76.873354)
		(end 449.169028 -76.637896)
		(width 0.254)
		(layer "F.Cu")
		(net "GND")
	)
	(segment
		(start 176.555654 -115.375436)
		(end 176.155604 -115.775486)
		(width 0.3556)
		(layer "F.Cu")
		(net "GND")
	)
	(segment
		(start 463.659982 -316.316614)
		(end 462.555082 -316.316614)
		(width 0.381)
		(layer "F.Cu")
		(net "GND")
	)
	(segment
		(start 97.653094 -279.96388)
		(end 97.653348 -279.964134)
		(width 0.254)
		(layer "F.Cu")
		(net "GND")
	)
	(segment
		(start 211.619846 -265.316716)
		(end 212.724746 -265.316716)
		(width 0.381)
		(layer "F.Cu")
		(net "GND")
	)
	(segment
		(start 215.719914 -294.216582)
		(end 216.824814 -294.216582)
		(width 0.381)
		(layer "F.Cu")
		(net "GND")
	)
	(segment
		(start 266.619482 -291.666676)
		(end 267.724382 -291.666676)
		(width 0.381)
		(layer "F.Cu")
		(net "GND")
	)
	(segment
		(start 337.49488 -238.76127)
		(end 337.49488 -238.225584)
		(width 0.254)
		(layer "F.Cu")
		(net "GND")
	)
	(segment
		(start 449.072508 -93.509592)
		(end 449.71208 -93.509592)
		(width 0.3556)
		(layer "F.Cu")
		(net "GND")
	)
	(segment
		(start 281.707082 -269.566644)
		(end 282.811982 -269.566644)
		(width 0.381)
		(layer "F.Cu")
		(net "GND")
	)
	(segment
		(start 282.811982 -272.966688)
		(end 283.916882 -272.966688)
		(width 0.381)
		(layer "F.Cu")
		(net "GND")
	)
	(segment
		(start 384.015234 -240.667286)
		(end 384.015234 -241.203226)
		(width 0.254)
		(layer "F.Cu")
		(net "GND")
	)
	(segment
		(start 197.637146 -227.066602)
		(end 196.532246 -227.066602)
		(width 0.381)
		(layer "F.Cu")
		(net "GND")
	)
	(segment
		(start 161.78784 -130.15595)
		(end 161.78784 -131.064508)
		(width 0.3556)
		(layer "F.Cu")
		(net "GND")
	)
	(segment
		(start 48.854614 -284.866588)
		(end 49.959514 -284.866588)
		(width 0.381)
		(layer "F.Cu")
		(net "GND")
	)
	(segment
		(start 166.357046 -199.01662)
		(end 165.252146 -199.01662)
		(width 0.381)
		(layer "F.Cu")
		(net "GND")
	)
	(segment
		(start 347.472762 -271.289272)
		(end 347.473016 -271.289526)
		(width 0.2032)
		(layer "F.Cu")
		(net "GND")
	)
	(segment
		(start 100.832666 -238.761524)
		(end 100.832412 -238.76127)
		(width 0.2032)
		(layer "F.Cu")
		(net "GND")
	)
	(segment
		(start 380.256034 -234.691936)
		(end 380.256034 -234.15625)
		(width 0.2032)
		(layer "F.Cu")
		(net "GND")
	)
	(segment
		(start 276.373082 -282.316682)
		(end 275.268182 -282.316682)
		(width 0.381)
		(layer "F.Cu")
		(net "GND")
	)
	(segment
		(start 124.327412 -232.250234)
		(end 124.327412 -231.714548)
		(width 0.254)
		(layer "F.Cu")
		(net "GND")
	)
	(segment
		(start 69.172582 -30.53461)
		(end 69.172582 -29.29001)
		(width 0.17272)
		(layer "F.Cu")
		(net "GND")
	)
	(segment
		(start 22.123146 -250.016772)
		(end 23.228046 -250.016772)
		(width 0.381)
		(layer "F.Cu")
		(net "GND")
	)
	(segment
		(start 115.399312 -226.017582)
		(end 115.399566 -226.017328)
		(width 0.254)
		(layer "F.Cu")
		(net "GND")
	)
	(segment
		(start 386.474716 -285.125414)
		(end 386.474716 -285.6611)
		(width 0.2032)
		(layer "F.Cu")
		(net "GND")
	)
	(segment
		(start 300.637702 -423.954448)
		(end 301.190406 -424.507152)
		(width 0.3556)
		(layer "F.Cu")
		(net "GND")
	)
	(segment
		(start 286.255714 -289.11677)
		(end 287.360614 -289.11677)
		(width 0.381)
		(layer "F.Cu")
		(net "GND")
	)
	(segment
		(start 263.624314 -281.466798)
		(end 264.729214 -281.466798)
		(width 0.381)
		(layer "F.Cu")
		(net "GND")
	)
	(segment
		(start 136.184894 -263.686544)
		(end 136.184894 -263.150604)
		(width 0.254)
		(layer "F.Cu")
		(net "GND")
	)
	(segment
		(start 159.718248 -236.416596)
		(end 159.737806 -236.397038)
		(width 0.381)
		(layer "F.Cu")
		(net "GND")
	)
	(segment
		(start 433.484782 -219.41663)
		(end 434.589682 -219.41663)
		(width 0.381)
		(layer "F.Cu")
		(net "GND")
	)
	(segment
		(start 262.519414 -265.316716)
		(end 263.624314 -265.316716)
		(width 0.381)
		(layer "F.Cu")
		(net "GND")
	)
	(segment
		(start 60.947046 -197.316598)
		(end 62.051946 -197.316598)
		(width 0.381)
		(layer "F.Cu")
		(net "GND")
	)
	(segment
		(start 30.771846 -197.316598)
		(end 31.876746 -197.316598)
		(width 0.381)
		(layer "F.Cu")
		(net "GND")
	)
	(segment
		(start 312.987182 -289.966654)
		(end 314.092082 -289.966654)
		(width 0.381)
		(layer "F.Cu")
		(net "GND")
	)
	(segment
		(start 331.608176 -50.329846)
		(end 331.880718 -50.799746)
		(width 0.2032)
		(layer "F.Cu")
		(net "GND")
	)
	(segment
		(start 312.709052 -15.64132)
		(end 313.17057 -15.64132)
		(width 0.3556)
		(layer "F.Cu")
		(net "GND")
	)
	(segment
		(start 358.280716 -280.77795)
		(end 358.280462 -280.778204)
		(width 0.254)
		(layer "F.Cu")
		(net "GND")
	)
	(segment
		(start 199.527414 -233.86669)
		(end 200.632314 -233.86669)
		(width 0.381)
		(layer "F.Cu")
		(net "GND")
	)
	(segment
		(start 122.558048 -262.336534)
		(end 122.558048 -262.872474)
		(width 0.2032)
		(layer "F.Cu")
		(net "GND")
	)
	(segment
		(start 22.123146 -298.466764)
		(end 23.228046 -298.466764)
		(width 0.381)
		(layer "F.Cu")
		(net "GND")
	)
	(segment
		(start 344.183716 -283.497782)
		(end 344.183716 -284.033468)
		(width 0.254)
		(layer "F.Cu")
		(net "GND")
	)
	(segment
		(start 158.813246 -307.816758)
		(end 159.918146 -307.816758)
		(width 0.381)
		(layer "F.Cu")
		(net "GND")
	)
	(segment
		(start 294.904414 -203.266802)
		(end 293.799514 -203.266802)
		(width 0.381)
		(layer "F.Cu")
		(net "GND")
	)
	(segment
		(start 196.532246 -216.016586)
		(end 197.637146 -216.016586)
		(width 0.381)
		(layer "F.Cu")
		(net "GND")
	)
	(segment
		(start 456.116182 -306.96662)
		(end 455.011282 -306.96662)
		(width 0.381)
		(layer "F.Cu")
		(net "GND")
	)
	(segment
		(start 423.564558 -367.67643)
		(end 423.096436 -367.208308)
		(width 0.381)
		(layer "F.Cu")
		(net "GND")
	)
	(segment
		(start 56.398414 -280.61666)
		(end 57.503314 -280.61666)
		(width 0.381)
		(layer "F.Cu")
		(net "GND")
	)
	(segment
		(start 444.472314 -279.766776)
		(end 445.577214 -279.766776)
		(width 0.381)
		(layer "F.Cu")
		(net "GND")
	)
	(segment
		(start 107.990894 -276.172676)
		(end 107.990894 -276.708362)
		(width 0.2032)
		(layer "F.Cu")
		(net "GND")
	)
	(segment
		(start 162.913314 -291.666676)
		(end 164.018214 -291.666676)
		(width 0.381)
		(layer "F.Cu")
		(net "GND")
	)
	(segment
		(start 200.632314 -213.46668)
		(end 201.737214 -213.46668)
		(width 0.381)
		(layer "F.Cu")
		(net "GND")
	)
	(segment
		(start 383.07518 -216.250774)
		(end 383.075434 -216.25052)
		(width 0.254)
		(layer "F.Cu")
		(net "GND")
	)
	(segment
		(start 410.853382 -297.616626)
		(end 409.748482 -297.616626)
		(width 0.381)
		(layer "F.Cu")
		(net "GND")
	)
	(segment
		(start 346.063316 -261.244588)
		(end 346.063062 -261.244842)
		(width 0.2032)
		(layer "F.Cu")
		(net "GND")
	)
	(segment
		(start 43.520614 -312.91657)
		(end 42.415714 -312.91657)
		(width 0.381)
		(layer "F.Cu")
		(net "GND")
	)
	(segment
		(start 372.607332 -61.581792)
		(end 372.607332 -62.216792)
		(width 0.3556)
		(layer "F.Cu")
		(net "GND")
	)
	(segment
		(start 425.940982 -221.116652)
		(end 427.045882 -221.116652)
		(width 0.381)
		(layer "F.Cu")
		(net "GND")
	)
	(segment
		(start 254.975614 -231.316784)
		(end 256.080514 -231.316784)
		(width 0.381)
		(layer "F.Cu")
		(net "GND")
	)
	(segment
		(start 129.136648 -273.730974)
		(end 129.136394 -274.266914)
		(width 0.2032)
		(layer "F.Cu")
		(net "GND")
	)
	(segment
		(start 375.087134 -224.111566)
		(end 375.087134 -223.575626)
		(width 0.2032)
		(layer "F.Cu")
		(net "GND")
	)
	(segment
		(start 371.79758 -223.297496)
		(end 371.79758 -222.76181)
		(width 0.254)
		(layer "F.Cu")
		(net "GND")
	)
	(segment
		(start 94.364048 -269.383256)
		(end 94.363794 -269.38351)
		(width 0.2032)
		(layer "F.Cu")
		(net "GND")
	)
	(segment
		(start 418.356796 -8.320024)
		(end 418.356796 -7.215124)
		(width 0.3556)
		(layer "F.Cu")
		(net "GND")
	)
	(segment
		(start 410.853382 -215.166702)
		(end 411.973522 -215.166702)
		(width 0.381)
		(layer "F.Cu")
		(net "GND")
	)
	(segment
		(start 95.193612 -245.272306)
		(end 95.193612 -244.73662)
		(width 0.2032)
		(layer "F.Cu")
		(net "GND")
	)
	(segment
		(start 363.33938 -223.297496)
		(end 363.33938 -222.76181)
		(width 0.254)
		(layer "F.Cu")
		(net "GND")
	)
	(segment
		(start 132.895848 -260.708902)
		(end 132.895848 -261.244588)
		(width 0.2032)
		(layer "F.Cu")
		(net "GND")
	)
	(segment
		(start 208.176114 -301.01667)
		(end 209.281014 -301.01667)
		(width 0.381)
		(layer "F.Cu")
		(net "GND")
	)
	(segment
		(start 196.532246 -208.366614)
		(end 197.637146 -208.366614)
		(width 0.381)
		(layer "F.Cu")
		(net "GND")
	)
	(segment
		(start 424.836082 -262.76681)
		(end 425.940982 -262.76681)
		(width 0.381)
		(layer "F.Cu")
		(net "GND")
	)
	(segment
		(start 200.632314 -249.166634)
		(end 201.737214 -249.166634)
		(width 0.381)
		(layer "F.Cu")
		(net "GND")
	)
	(segment
		(start 405.139144 -62.994032)
		(end 404.346156 -62.994032)
		(width 0.3556)
		(layer "F.Cu")
		(net "GND")
	)
	(segment
		(start 129.496312 -236.319822)
		(end 129.496566 -236.319568)
		(width 0.2032)
		(layer "F.Cu")
		(net "GND")
	)
	(segment
		(start 425.940982 -280.61666)
		(end 424.836082 -280.61666)
		(width 0.381)
		(layer "F.Cu")
		(net "GND")
	)
	(segment
		(start 27.328114 -284.866588)
		(end 28.433014 -284.866588)
		(width 0.381)
		(layer "F.Cu")
		(net "GND")
	)
	(segment
		(start 49.959514 -277.216616)
		(end 51.064414 -277.216616)
		(width 0.381)
		(layer "F.Cu")
		(net "GND")
	)
	(segment
		(start 457.221082 -275.516594)
		(end 456.116182 -275.516594)
		(width 0.381)
		(layer "F.Cu")
		(net "GND")
	)
	(segment
		(start 99.422712 -242.830858)
		(end 99.422712 -242.295172)
		(width 0.2032)
		(layer "F.Cu")
		(net "GND")
	)
	(segment
		(start 88.145366 -229.272846)
		(end 88.145366 -229.808786)
		(width 0.2032)
		(layer "F.Cu")
		(net "GND")
	)
	(segment
		(start 193.088514 -282.316682)
		(end 194.193414 -282.316682)
		(width 0.381)
		(layer "F.Cu")
		(net "GND")
	)
	(segment
		(start 133.255512 -237.947454)
		(end 133.255512 -237.411514)
		(width 0.254)
		(layer "F.Cu")
		(net "GND")
	)
	(segment
		(start 208.176114 -213.46668)
		(end 209.281014 -213.46668)
		(width 0.381)
		(layer "F.Cu")
		(net "GND")
	)
	(segment
		(start 125.847094 -258.2672)
		(end 125.847094 -258.802886)
		(width 0.2032)
		(layer "F.Cu")
		(net "GND")
	)
	(segment
		(start 453.121014 -216.016586)
		(end 452.016114 -216.016586)
		(width 0.381)
		(layer "F.Cu")
		(net "GND")
	)
	(segment
		(start 459.559914 -270.416782)
		(end 458.455014 -270.416782)
		(width 0.381)
		(layer "F.Cu")
		(net "GND")
	)
	(segment
		(start 354.88118 -226.017582)
		(end 354.881434 -226.017328)
		(width 0.254)
		(layer "F.Cu")
		(net "GND")
	)
	(segment
		(start 385.534662 -263.96442)
		(end 385.093464 -263.709404)
		(width 0.254)
		(layer "F.Cu")
		(net "GND")
	)
	(segment
		(start 290.355782 -194.766692)
		(end 291.460682 -194.766692)
		(width 0.381)
		(layer "F.Cu")
		(net "GND")
	)
	(segment
		(start 278.711914 -203.266802)
		(end 279.816814 -203.266802)
		(width 0.381)
		(layer "F.Cu")
		(net "GND")
	)
	(segment
		(start 174.43704 -56.619648)
		(end 175.217328 -57.399936)
		(width 0.3556)
		(layer "F.Cu")
		(net "GND")
	)
	(segment
		(start 304.338482 -269.566644)
		(end 305.443382 -269.566644)
		(width 0.381)
		(layer "F.Cu")
		(net "GND")
	)
	(segment
		(start 129.026666 -238.761524)
		(end 129.026412 -238.76127)
		(width 0.2032)
		(layer "F.Cu")
		(net "GND")
	)
	(segment
		(start 183.86044 -13.598398)
		(end 183.86044 -12.817348)
		(width 0.3556)
		(layer "F.Cu")
		(net "GND")
	)
	(segment
		(start 413.760412 -362.562648)
		(end 413.43326 -362.562648)
		(width 0.2032)
		(layer "F.Cu")
		(net "GND")
	)
	(segment
		(start 301.343314 -201.56678)
		(end 302.448214 -201.56678)
		(width 0.381)
		(layer "F.Cu")
		(net "GND")
	)
	(segment
		(start 366.13846 -56.911748)
		(end 365.810546 -56.583834)
		(width 0.3556)
		(layer "F.Cu")
		(net "GND")
	)
	(segment
		(start 85.325712 -247.714262)
		(end 84.856066 -247.992138)
		(width 0.2032)
		(layer "F.Cu")
		(net "GND")
	)
	(segment
		(start 335.255362 -255.011682)
		(end 335.255362 -255.547622)
		(width 0.2032)
		(layer "F.Cu")
		(net "GND")
	)
	(segment
		(start 102.135686 -336.040222)
		(end 101.58349 -336.592418)
		(width 0.1778)
		(layer "F.Cu")
		(net "GND")
	)
	(segment
		(start 372.267734 -246.900446)
		(end 372.26748 -246.900192)
		(width 0.2032)
		(layer "F.Cu")
		(net "GND")
	)
	(segment
		(start 457.221082 -303.566576)
		(end 456.116182 -303.566576)
		(width 0.381)
		(layer "F.Cu")
		(net "GND")
	)
	(segment
		(start 199.527414 -294.216582)
		(end 200.632314 -294.216582)
		(width 0.381)
		(layer "F.Cu")
		(net "GND")
	)
	(segment
		(start 32.434022 -168.02481)
		(end 31.940246 -168.02481)
		(width 0.381)
		(layer "F.Cu")
		(net "GND")
	)
	(segment
		(start 334.174846 -17.935702)
		(end 333.944214 -17.70507)
		(width 0.3556)
		(layer "F.Cu")
		(net "GND")
	)
	(segment
		(start 19.784314 -264.466578)
		(end 20.889214 -264.466578)
		(width 0.381)
		(layer "F.Cu")
		(net "GND")
	)
	(segment
		(start 161.935414 -286.56661)
		(end 161.808414 -286.69361)
		(width 0.381)
		(layer "F.Cu")
		(net "GND")
	)
	(segment
		(start 104.231694 -278.336248)
		(end 104.231948 -278.336502)
		(width 0.2032)
		(layer "F.Cu")
		(net "GND")
	)
	(segment
		(start 116.399056 -66.264028)
		(end 116.399056 -64.734948)
		(width 0.3556)
		(layer "F.Cu")
		(net "GND")
	)
	(segment
		(start 350.762316 -270.475456)
		(end 350.762062 -270.47571)
		(width 0.2032)
		(layer "F.Cu")
		(net "GND")
	)
	(segment
		(start 412.374334 -29.785818)
		(end 412.465774 -29.877258)
		(width 0.3556)
		(layer "F.Cu")
		(net "GND")
	)
	(segment
		(start 211.619846 -307.816758)
		(end 210.514946 -307.816758)
		(width 0.381)
		(layer "F.Cu")
		(net "GND")
	)
	(segment
		(start 107.051094 -278.336248)
		(end 107.051348 -278.336502)
		(width 0.254)
		(layer "F.Cu")
		(net "GND")
	)
	(segment
		(start 114.929412 -215.97239)
		(end 114.929412 -215.436704)
		(width 0.2032)
		(layer "F.Cu")
		(net "GND")
	)
	(segment
		(start 263.624314 -298.466764)
		(end 264.729214 -298.466764)
		(width 0.381)
		(layer "F.Cu")
		(net "GND")
	)
	(segment
		(start 211.619846 -246.616728)
		(end 212.724746 -246.616728)
		(width 0.381)
		(layer "F.Cu")
		(net "GND")
	)
	(segment
		(start 131.016248 -286.7533)
		(end 131.016248 -287.288986)
		(width 0.254)
		(layer "F.Cu")
		(net "GND")
	)
	(segment
		(start 413.192214 -278.066754)
		(end 414.297114 -278.066754)
		(width 0.381)
		(layer "F.Cu")
		(net "GND")
	)
	(segment
		(start 343.547954 -48.449992)
		(end 343.819734 -48.919892)
		(width 0.254)
		(layer "F.Cu")
		(net "GND")
	)
	(segment
		(start 328.648822 -60.327032)
		(end 328.895964 -60.07989)
		(width 0.254)
		(layer "F.Cu")
		(net "GND")
	)
	(segment
		(start 341.72398 -242.295172)
		(end 341.724234 -242.294918)
		(width 0.2032)
		(layer "F.Cu")
		(net "GND")
	)
	(segment
		(start 99.422712 -239.57534)
		(end 99.422966 -239.575086)
		(width 0.2032)
		(layer "F.Cu")
		(net "GND")
	)
	(segment
		(start 339.484716 -254.197612)
		(end 339.484716 -254.733552)
		(width 0.2032)
		(layer "F.Cu")
		(net "GND")
	)
	(segment
		(start 448.572382 -291.666676)
		(end 447.467482 -291.666676)
		(width 0.381)
		(layer "F.Cu")
		(net "GND")
	)
	(segment
		(start 308.887114 -229.616762)
		(end 309.992014 -229.616762)
		(width 0.381)
		(layer "F.Cu")
		(net "GND")
	)
	(segment
		(start 89.554812 -240.388902)
		(end 89.554812 -239.853216)
		(width 0.2032)
		(layer "F.Cu")
		(net "GND")
	)
	(segment
		(start 345.013534 -220.855794)
		(end 345.013534 -220.319854)
		(width 0.2032)
		(layer "F.Cu")
		(net "GND")
	)
	(segment
		(start 301.343314 -212.616796)
		(end 302.448214 -212.616796)
		(width 0.381)
		(layer "F.Cu")
		(net "GND")
	)
	(segment
		(start 105.312464 -238.562642)
		(end 105.179622 -238.695484)
		(width 0.254)
		(layer "F.Cu")
		(net "GND")
	)
	(segment
		(start 38.315646 -304.416714)
		(end 37.210746 -304.416714)
		(width 0.381)
		(layer "F.Cu")
		(net "GND")
	)
	(segment
		(start 212.39734 -69.86143)
		(end 212.39734 -71.13143)
		(width 0.3556)
		(layer "F.Cu")
		(net "GND")
	)
	(segment
		(start 432.379882 -275.516594)
		(end 433.484782 -275.516594)
		(width 0.381)
		(layer "F.Cu")
		(net "GND")
	)
	(segment
		(start 300.022514 -210.916774)
		(end 301.343314 -210.916774)
		(width 0.381)
		(layer "F.Cu")
		(net "GND")
	)
	(segment
		(start 425.940982 -247.466612)
		(end 427.045882 -247.466612)
		(width 0.381)
		(layer "F.Cu")
		(net "GND")
	)
	(segment
		(start 329.89647 -39.295324)
		(end 330.396596 -39.443152)
		(width 0.2032)
		(layer "F.Cu")
		(net "GND")
	)
	(segment
		(start 125.737366 -239.575086)
		(end 125.737366 -239.0394)
		(width 0.2032)
		(layer "F.Cu")
		(net "GND")
	)
	(segment
		(start 373.787162 -281.05608)
		(end 373.787416 -281.056334)
		(width 0.254)
		(layer "F.Cu")
		(net "GND")
	)
	(segment
		(start 348.412562 -285.939484)
		(end 348.412562 -286.475424)
		(width 0.2032)
		(layer "F.Cu")
		(net "GND")
	)
	(segment
		(start 427.045882 -301.01667)
		(end 425.940982 -301.01667)
		(width 0.381)
		(layer "F.Cu")
		(net "GND")
	)
	(segment
		(start 304.122582 -219.41663)
		(end 305.443382 -219.41663)
		(width 0.381)
		(layer "F.Cu")
		(net "GND")
	)
	(segment
		(start 208.176114 -226.216718)
		(end 209.281014 -226.216718)
		(width 0.381)
		(layer "F.Cu")
		(net "GND")
	)
	(segment
		(start 433.484782 -271.266666)
		(end 434.589682 -271.266666)
		(width 0.381)
		(layer "F.Cu")
		(net "GND")
	)
	(segment
		(start 365.441484 -389.838184)
		(end 364.88878 -390.390888)
		(width 0.3556)
		(layer "F.Cu")
		(net "GND")
	)
	(segment
		(start 150.93188 -109.419898)
		(end 150.29688 -109.419898)
		(width 0.3556)
		(layer "F.Cu")
		(net "GND")
	)
	(segment
		(start 106.471466 -233.87812)
		(end 106.471212 -233.877866)
		(width 0.2032)
		(layer "F.Cu")
		(net "GND")
	)
	(segment
		(start 267.724382 -291.666676)
		(end 268.829282 -291.666676)
		(width 0.381)
		(layer "F.Cu")
		(net "GND")
	)
	(segment
		(start 384.124962 -268.033754)
		(end 384.124962 -268.569694)
		(width 0.254)
		(layer "F.Cu")
		(net "GND")
	)
	(segment
		(start 53.403246 -204.96657)
		(end 52.298346 -204.96657)
		(width 0.381)
		(layer "F.Cu")
		(net "GND")
	)
	(segment
		(start 96.133666 -248.528078)
		(end 96.133666 -247.992138)
		(width 0.2032)
		(layer "F.Cu")
		(net "GND")
	)
	(segment
		(start 382.605534 -217.600276)
		(end 382.605534 -217.064336)
		(width 0.2032)
		(layer "F.Cu")
		(net "GND")
	)
	(segment
		(start 192.63868 -113.706148)
		(end 193.09588 -113.706148)
		(width 0.3556)
		(layer "F.Cu")
		(net "GND")
	)
	(segment
		(start 300.238414 -212.616796)
		(end 301.343314 -212.616796)
		(width 0.381)
		(layer "F.Cu")
		(net "GND")
	)
	(segment
		(start 126.677166 -220.041724)
		(end 126.677166 -219.506038)
		(width 0.254)
		(layer "F.Cu")
		(net "GND")
	)
	(segment
		(start 116.449094 -284.847284)
		(end 116.449348 -284.847538)
		(width 0.254)
		(layer "F.Cu")
		(net "GND")
	)
	(segment
		(start 214.615014 -288.266632)
		(end 215.719914 -288.266632)
		(width 0.381)
		(layer "F.Cu")
		(net "GND")
	)
	(segment
		(start 460.664814 -250.016772)
		(end 459.559914 -250.016772)
		(width 0.381)
		(layer "F.Cu")
		(net "GND")
	)
	(segment
		(start 427.045882 -239.81664)
		(end 425.940982 -239.81664)
		(width 0.381)
		(layer "F.Cu")
		(net "GND")
	)
	(segment
		(start 44.754546 -234.716574)
		(end 45.859446 -234.716574)
		(width 0.381)
		(layer "F.Cu")
		(net "GND")
	)
	(segment
		(start 380.25578 -226.017582)
		(end 380.256034 -226.017328)
		(width 0.254)
		(layer "F.Cu")
		(net "GND")
	)
	(segment
		(start 32.561022 -168.15181)
		(end 32.434022 -168.02481)
		(width 0.381)
		(layer "F.Cu")
		(net "GND")
	)
	(segment
		(start 467.044278 -38.456108)
		(end 467.679278 -38.456108)
		(width 0.3556)
		(layer "F.Cu")
		(net "GND")
	)
	(segment
		(start 436.928514 -311.216802)
		(end 438.033414 -311.216802)
		(width 0.381)
		(layer "F.Cu")
		(net "GND")
	)
	(segment
		(start 196.532246 -273.816572)
		(end 195.427346 -273.816572)
		(width 0.381)
		(layer "F.Cu")
		(net "GND")
	)
	(segment
		(start 11.135614 -215.166702)
		(end 12.240514 -215.166702)
		(width 0.381)
		(layer "F.Cu")
		(net "GND")
	)
	(segment
		(start 456.116182 -241.516662)
		(end 457.221082 -241.516662)
		(width 0.381)
		(layer "F.Cu")
		(net "GND")
	)
	(segment
		(start 358.280716 -257.45313)
		(end 358.280716 -257.988816)
		(width 0.254)
		(layer "F.Cu")
		(net "GND")
	)
	(segment
		(start 448.572382 -277.216616)
		(end 447.467482 -277.216616)
		(width 0.381)
		(layer "F.Cu")
		(net "GND")
	)
	(segment
		(start 199.527414 -306.96662)
		(end 200.632314 -306.96662)
		(width 0.381)
		(layer "F.Cu")
		(net "GND")
	)
	(segment
		(start 261.285482 -224.516696)
		(end 260.180582 -224.516696)
		(width 0.381)
		(layer "F.Cu")
		(net "GND")
	)
	(segment
		(start 120.568212 -233.877866)
		(end 120.568212 -233.34218)
		(width 0.254)
		(layer "F.Cu")
		(net "GND")
	)
	(segment
		(start 336.899758 -39.295324)
		(end 336.399632 -38.880288)
		(width 0.2032)
		(layer "F.Cu")
		(net "GND")
	)
	(segment
		(start 271.168114 -315.46673)
		(end 270.063214 -315.46673)
		(width 0.381)
		(layer "F.Cu")
		(net "GND")
	)
	(segment
		(start 266.619482 -278.916638)
		(end 267.724382 -278.916638)
		(width 0.381)
		(layer "F.Cu")
		(net "GND")
	)
	(segment
		(start 106.941112 -226.553268)
		(end 106.941112 -226.017582)
		(width 0.254)
		(layer "F.Cu")
		(net "GND")
	)
	(segment
		(start 120.208294 -279.96388)
		(end 120.208548 -279.964134)
		(width 0.254)
		(layer "F.Cu")
		(net "GND")
	)
	(segment
		(start 380.25578 -234.69219)
		(end 380.256034 -234.691936)
		(width 0.2032)
		(layer "F.Cu")
		(net "GND")
	)
	(segment
		(start 294.904414 -290.816792)
		(end 293.799514 -290.816792)
		(width 0.381)
		(layer "F.Cu")
		(net "GND")
	)
	(segment
		(start 144.564608 -105.768648)
		(end 144.564608 -105.174796)
		(width 0.3556)
		(layer "F.Cu")
		(net "GND")
	)
	(segment
		(start 406.753314 -233.016806)
		(end 407.858214 -233.016806)
		(width 0.381)
		(layer "F.Cu")
		(net "GND")
	)
	(segment
		(start 439.923682 -278.916638)
		(end 441.028582 -278.916638)
		(width 0.381)
		(layer "F.Cu")
		(net "GND")
	)
	(segment
		(start 286.255714 -244.916706)
		(end 287.360614 -244.916706)
		(width 0.381)
		(layer "F.Cu")
		(net "GND")
	)
	(segment
		(start 60.947046 -240.666778)
		(end 62.051946 -240.666778)
		(width 0.381)
		(layer "F.Cu")
		(net "GND")
	)
	(segment
		(start 21.581364 -95.510604)
		(end 22.264116 -95.510604)
		(width 0.3556)
		(layer "F.Cu")
		(net "GND")
	)
	(segment
		(start 261.285482 -291.666676)
		(end 260.180582 -291.666676)
		(width 0.381)
		(layer "F.Cu")
		(net "GND")
	)
	(segment
		(start 339.954362 -279.428194)
		(end 339.954362 -279.96388)
		(width 0.254)
		(layer "F.Cu")
		(net "GND")
	)
	(segment
		(start 39.420546 -295.06672)
		(end 38.315646 -295.06672)
		(width 0.381)
		(layer "F.Cu")
		(net "GND")
	)
	(segment
		(start 33.767014 -213.46668)
		(end 34.871914 -213.46668)
		(width 0.381)
		(layer "F.Cu")
		(net "GND")
	)
	(segment
		(start 330.896976 -38.465252)
		(end 330.896976 -39.295324)
		(width 0.254)
		(layer "F.Cu")
		(net "GND")
	)
	(segment
		(start 365.799116 -265.592306)
		(end 365.799116 -266.127992)
		(width 0.2032)
		(layer "F.Cu")
		(net "GND")
	)
	(segment
		(start 301.45482 -418.62756)
		(end 301.45482 -417.990528)
		(width 0.3556)
		(layer "F.Cu")
		(net "GND")
	)
	(segment
		(start 135.400288 -343.391998)
		(end 135.106664 -343.391998)
		(width 0.2032)
		(layer "F.Cu")
		(net "GND")
	)
	(segment
		(start 394.899642 -57.030366)
		(end 394.899896 -57.03062)
		(width 0.3556)
		(layer "F.Cu")
		(net "GND")
	)
	(segment
		(start 43.520614 -286.56661)
		(end 42.415714 -286.56661)
		(width 0.381)
		(layer "F.Cu")
		(net "GND")
	)
	(segment
		(start 378.84608 -250.15571)
		(end 378.84608 -249.620024)
		(width 0.2032)
		(layer "F.Cu")
		(net "GND")
	)
	(segment
		(start 285.150814 -197.316598)
		(end 286.255714 -197.316598)
		(width 0.381)
		(layer "F.Cu")
		(net "GND")
	)
	(segment
		(start 441.028582 -239.81664)
		(end 442.133482 -239.81664)
		(width 0.381)
		(layer "F.Cu")
		(net "GND")
	)
	(segment
		(start 328.625708 -48.450246)
		(end 328.244962 -47.95012)
		(width 0.1778)
		(layer "F.Cu")
		(net "GND")
	)
	(segment
		(start 412.953962 -236.416596)
		(end 414.297114 -236.416596)
		(width 0.381)
		(layer "F.Cu")
		(net "GND")
	)
	(segment
		(start 370.498116 -270.475456)
		(end 370.498116 -271.011396)
		(width 0.254)
		(layer "F.Cu")
		(net "GND")
	)
	(segment
		(start 448.572382 -269.566644)
		(end 447.467482 -269.566644)
		(width 0.381)
		(layer "F.Cu")
		(net "GND")
	)
	(segment
		(start 378.84608 -228.994716)
		(end 378.84608 -228.45903)
		(width 0.2032)
		(layer "F.Cu")
		(net "GND")
	)
	(segment
		(start 122.558048 -287.288986)
		(end 122.557794 -287.28924)
		(width 0.254)
		(layer "F.Cu")
		(net "GND")
	)
	(segment
		(start 214.615014 -216.866724)
		(end 215.719914 -216.866724)
		(width 0.381)
		(layer "F.Cu")
		(net "GND")
	)
	(segment
		(start 134.195566 -244.458744)
		(end 134.195566 -243.922804)
		(width 0.2032)
		(layer "F.Cu")
		(net "GND")
	)
	(segment
		(start 115.399312 -222.76181)
		(end 115.399566 -222.761556)
		(width 0.254)
		(layer "F.Cu")
		(net "GND")
	)
	(segment
		(start 38.315646 -250.016772)
		(end 37.210746 -250.016772)
		(width 0.381)
		(layer "F.Cu")
		(net "GND")
	)
	(segment
		(start 272.273014 -208.366614)
		(end 271.168114 -208.366614)
		(width 0.381)
		(layer "F.Cu")
		(net "GND")
	)
	(segment
		(start 197.637146 -295.06672)
		(end 196.532246 -295.06672)
		(width 0.381)
		(layer "F.Cu")
		(net "GND")
	)
	(segment
		(start 386.364734 -235.506006)
		(end 385.894834 -235.783882)
		(width 0.254)
		(layer "F.Cu")
		(net "GND")
	)
	(segment
		(start 135.245348 -270.167862)
		(end 135.245348 -270.19758)
		(width 0.2032)
		(layer "F.Cu")
		(net "GND")
	)
	(segment
		(start 369.917726 -237.412022)
		(end 369.918234 -237.411514)
		(width 0.254)
		(layer "F.Cu")
		(net "GND")
	)
	(segment
		(start 102.821994 -268.847824)
		(end 102.821994 -269.38351)
		(width 0.2032)
		(layer "F.Cu")
		(net "GND")
	)
	(segment
		(start 452.016114 -298.466764)
		(end 450.911214 -298.466764)
		(width 0.381)
		(layer "F.Cu")
		(net "GND")
	)
	(segment
		(start 97.543366 -244.45849)
		(end 97.543366 -243.922804)
		(width 0.2032)
		(layer "F.Cu")
		(net "GND")
	)
	(segment
		(start 289.182048 -13.443204)
		(end 287.745424 -13.443204)
		(width 0.3556)
		(layer "F.Cu")
		(net "GND")
	)
	(segment
		(start 188.988446 -227.066602)
		(end 190.093346 -227.066602)
		(width 0.381)
		(layer "F.Cu")
		(net "GND")
	)
	(segment
		(start 458.32014 -382.83388)
		(end 458.32014 -382.473454)
		(width 0.1778)
		(layer "F.Cu")
		(net "GND")
	)
	(segment
		(start 106.001312 -229.808786)
		(end 106.001566 -229.808532)
		(width 0.2032)
		(layer "F.Cu")
		(net "GND")
	)
	(segment
		(start 23.228046 -250.016772)
		(end 24.332946 -250.016772)
		(width 0.381)
		(layer "F.Cu")
		(net "GND")
	)
	(segment
		(start 179.105814 -226.216718)
		(end 178.000914 -226.216718)
		(width 0.381)
		(layer "F.Cu")
		(net "GND")
	)
	(segment
		(start 296.794682 -299.316648)
		(end 297.899582 -299.316648)
		(width 0.381)
		(layer "F.Cu")
		(net "GND")
	)
	(segment
		(start 121.618248 -278.614378)
		(end 121.617994 -279.150318)
		(width 0.2032)
		(layer "F.Cu")
		(net "GND")
	)
	(segment
		(start 370.967762 -253.383796)
		(end 370.967762 -253.919736)
		(width 0.2032)
		(layer "F.Cu")
		(net "GND")
	)
	(segment
		(start 375.55678 -237.411768)
		(end 375.557034 -237.411514)
		(width 0.254)
		(layer "F.Cu")
		(net "GND")
	)
	(segment
		(start 52.298346 -298.466764)
		(end 53.403246 -298.466764)
		(width 0.381)
		(layer "F.Cu")
		(net "GND")
	)
	(segment
		(start 308.887114 -292.516814)
		(end 309.992014 -292.516814)
		(width 0.381)
		(layer "F.Cu")
		(net "GND")
	)
	(segment
		(start 86.375494 -253.383796)
		(end 85.90534 -253.10592)
		(width 0.2032)
		(layer "F.Cu")
		(net "GND")
	)
	(segment
		(start 346.42298 -216.78646)
		(end 346.42298 -216.250774)
		(width 0.254)
		(layer "F.Cu")
		(net "GND")
	)
	(segment
		(start 308.887114 -279.766776)
		(end 309.992014 -279.766776)
		(width 0.381)
		(layer "F.Cu")
		(net "GND")
	)
	(segment
		(start 278.711914 -248.31675)
		(end 279.816814 -248.31675)
		(width 0.381)
		(layer "F.Cu")
		(net "GND")
	)
	(segment
		(start 117.859048 -266.127992)
		(end 117.858794 -266.128246)
		(width 0.254)
		(layer "F.Cu")
		(net "GND")
	)
	(segment
		(start 289.250882 -272.966688)
		(end 290.355782 -272.966688)
		(width 0.381)
		(layer "F.Cu")
		(net "GND")
	)
	(segment
		(start 106.001312 -216.78646)
		(end 106.001312 -216.250774)
		(width 0.254)
		(layer "F.Cu")
		(net "GND")
	)
	(segment
		(start 30.771846 -260.21665)
		(end 31.876746 -260.21665)
		(width 0.381)
		(layer "F.Cu")
		(net "GND")
	)
	(segment
		(start 358.280716 -282.405582)
		(end 358.280462 -282.405836)
		(width 0.254)
		(layer "F.Cu")
		(net "GND")
	)
	(segment
		(start 130.906012 -230.622348)
		(end 130.906012 -230.086662)
		(width 0.2032)
		(layer "F.Cu")
		(net "GND")
	)
	(segment
		(start 307.782214 -195.616576)
		(end 308.887114 -195.616576)
		(width 0.381)
		(layer "F.Cu")
		(net "GND")
	)
	(segment
		(start 136.075166 -215.158574)
		(end 136.075166 -214.546434)
		(width 0.254)
		(layer "F.Cu")
		(net "GND")
	)
	(segment
		(start 293.799514 -304.416714)
		(end 292.694614 -304.416714)
		(width 0.381)
		(layer "F.Cu")
		(net "GND")
	)
	(segment
		(start 196.532246 -301.866808)
		(end 195.427346 -301.866808)
		(width 0.381)
		(layer "F.Cu")
		(net "GND")
	)
	(segment
		(start 333.375762 -259.894832)
		(end 333.845662 -259.616956)
		(width 0.254)
		(layer "F.Cu")
		(net "GND")
	)
	(segment
		(start 342.304116 -263.96442)
		(end 342.304116 -264.500106)
		(width 0.254)
		(layer "F.Cu")
		(net "GND")
	)
	(segment
		(start 29.666946 -287.416748)
		(end 30.771846 -287.416748)
		(width 0.381)
		(layer "F.Cu")
		(net "GND")
	)
	(segment
		(start 196.532246 -210.916774)
		(end 197.637146 -210.916774)
		(width 0.381)
		(layer "F.Cu")
		(net "GND")
	)
	(segment
		(start 112.40008 -122.532648)
		(end 112.40008 -123.148598)
		(width 0.3556)
		(layer "F.Cu")
		(net "GND")
	)
	(segment
		(start 184.439814 -222.816674)
		(end 185.544714 -222.816674)
		(width 0.381)
		(layer "F.Cu")
		(net "GND")
	)
	(segment
		(start 32.947102 -11.26998)
		(end 32.947102 -12.37488)
		(width 0.3556)
		(layer "F.Cu")
		(net "GND")
	)
	(segment
		(start 262.519414 -298.466764)
		(end 263.624314 -298.466764)
		(width 0.381)
		(layer "F.Cu")
		(net "GND")
	)
	(segment
		(start 293.799514 -311.216802)
		(end 292.694614 -311.216802)
		(width 0.381)
		(layer "F.Cu")
		(net "GND")
	)
	(segment
		(start 432.379882 -282.316682)
		(end 433.484782 -282.316682)
		(width 0.381)
		(layer "F.Cu")
		(net "GND")
	)
	(segment
		(start 167.258746 -287.416748)
		(end 166.357046 -287.416748)
		(width 0.381)
		(layer "F.Cu")
		(net "GND")
	)
	(segment
		(start 170.457114 -269.566644)
		(end 169.352214 -269.566644)
		(width 0.381)
		(layer "F.Cu")
		(net "GND")
	)
	(segment
		(start 59.842146 -234.716574)
		(end 60.947046 -234.716574)
		(width 0.381)
		(layer "F.Cu")
		(net "GND")
	)
	(segment
		(start 410.853382 -211.766658)
		(end 409.748482 -211.766658)
		(width 0.381)
		(layer "F.Cu")
		(net "GND")
	)
	(segment
		(start 137.808716 -117.536976)
		(end 136.782302 -117.536976)
		(width 0.3556)
		(layer "F.Cu")
		(net "GND")
	)
	(segment
		(start 49.959514 -207.51673)
		(end 51.064414 -207.51673)
		(width 0.381)
		(layer "F.Cu")
		(net "GND")
	)
	(segment
		(start 260.180582 -239.81664)
		(end 259.075682 -239.81664)
		(width 0.381)
		(layer "F.Cu")
		(net "GND")
	)
	(segment
		(start 414.297114 -248.31675)
		(end 415.402014 -248.31675)
		(width 0.381)
		(layer "F.Cu")
		(net "GND")
	)
	(segment
		(start 384.015234 -230.900478)
		(end 384.015234 -231.436418)
		(width 0.254)
		(layer "F.Cu")
		(net "GND")
	)
	(segment
		(start 347.363034 -241.202972)
		(end 347.363034 -240.667286)
		(width 0.2032)
		(layer "F.Cu")
		(net "GND")
	)
	(segment
		(start 418.397182 -238.116618)
		(end 417.08451 -238.116618)
		(width 0.381)
		(layer "F.Cu")
		(net "GND")
	)
	(segment
		(start 23.228046 -261.916672)
		(end 24.332946 -261.916672)
		(width 0.381)
		(layer "F.Cu")
		(net "GND")
	)
	(segment
		(start 106.471466 -232.250488)
		(end 106.471212 -232.250234)
		(width 0.254)
		(layer "F.Cu")
		(net "GND")
	)
	(segment
		(start 214.615014 -271.266666)
		(end 215.719914 -271.266666)
		(width 0.381)
		(layer "F.Cu")
		(net "GND")
	)
	(segment
		(start 285.150814 -273.816572)
		(end 286.255714 -273.816572)
		(width 0.381)
		(layer "F.Cu")
		(net "GND")
	)
	(segment
		(start 124.907548 -282.68422)
		(end 124.907548 -283.219906)
		(width 0.254)
		(layer "F.Cu")
		(net "GND")
	)
	(segment
		(start 421.840914 -278.066754)
		(end 420.736014 -278.066754)
		(width 0.381)
		(layer "F.Cu")
		(net "GND")
	)
	(segment
		(start 436.928514 -268.71676)
		(end 438.033414 -268.71676)
		(width 0.381)
		(layer "F.Cu")
		(net "GND")
	)
	(segment
		(start 22.147022 -10.16508)
		(end 22.147022 -11.26998)
		(width 0.3556)
		(layer "F.Cu")
		(net "GND")
	)
	(segment
		(start 115.219734 -92.329762)
		(end 115.219734 -91.199462)
		(width 0.3556)
		(layer "F.Cu")
		(net "GND")
	)
	(segment
		(start 130.436112 -222.76181)
		(end 130.436366 -222.761556)
		(width 0.254)
		(layer "F.Cu")
		(net "GND")
	)
	(segment
		(start 164.018214 -204.116686)
		(end 162.913314 -204.116686)
		(width 0.381)
		(layer "F.Cu")
		(net "GND")
	)
	(segment
		(start 463.659982 -277.216616)
		(end 462.555082 -277.216616)
		(width 0.381)
		(layer "F.Cu")
		(net "GND")
	)
	(segment
		(start 457.221082 -245.76659)
		(end 456.116182 -245.76659)
		(width 0.381)
		(layer "F.Cu")
		(net "GND")
	)
	(segment
		(start 19.784314 -291.666676)
		(end 20.889214 -291.666676)
		(width 0.381)
		(layer "F.Cu")
		(net "GND")
	)
	(segment
		(start 286.255714 -272.116804)
		(end 287.360614 -272.116804)
		(width 0.381)
		(layer "F.Cu")
		(net "GND")
	)
	(segment
		(start 35.976814 -301.01667)
		(end 34.871914 -301.01667)
		(width 0.381)
		(layer "F.Cu")
		(net "GND")
	)
	(segment
		(start 347.942916 -257.988816)
		(end 347.942662 -257.98907)
		(width 0.2032)
		(layer "F.Cu")
		(net "GND")
	)
	(segment
		(start 336.285332 -37.141658)
		(end 336.285332 -37.935916)
		(width 0.2032)
		(layer "F.Cu")
		(net "GND")
	)
	(segment
		(start 128.556512 -223.297496)
		(end 128.556512 -222.76181)
		(width 0.254)
		(layer "F.Cu")
		(net "GND")
	)
	(segment
		(start 29.666946 -268.71676)
		(end 30.771846 -268.71676)
		(width 0.381)
		(layer "F.Cu")
		(net "GND")
	)
	(segment
		(start 177.108104 -52.799996)
		(end 178.289204 -52.799996)
		(width 0.254)
		(layer "F.Cu")
		(net "GND")
	)
	(segment
		(start 195.427346 -307.816758)
		(end 196.532246 -307.816758)
		(width 0.381)
		(layer "F.Cu")
		(net "GND")
	)
	(segment
		(start 166.357046 -216.016586)
		(end 167.461946 -216.016586)
		(width 0.381)
		(layer "F.Cu")
		(net "GND")
	)
	(segment
		(start 384.494786 -66.973704)
		(end 384.764026 -66.704464)
		(width 0.3556)
		(layer "F.Cu")
		(net "GND")
	)
	(segment
		(start 378.96165 -106.850688)
		(end 378.96165 -107.183428)
		(width 0.3556)
		(layer "F.Cu")
		(net "GND")
	)
	(segment
		(start 123.497848 -280.242264)
		(end 123.497594 -280.778204)
		(width 0.2032)
		(layer "F.Cu")
		(net "GND")
	)
	(segment
		(start 374.257316 -273.730974)
		(end 374.257316 -274.266914)
		(width 0.2032)
		(layer "F.Cu")
		(net "GND")
	)
	(segment
		(start 121.508266 -217.600276)
		(end 121.508266 -217.064336)
		(width 0.254)
		(layer "F.Cu")
		(net "GND")
	)
	(segment
		(start 167.461946 -242.3668)
		(end 166.357046 -242.3668)
		(width 0.381)
		(layer "F.Cu")
		(net "GND")
	)
	(segment
		(start 333.214472 -278.614378)
		(end 333.845662 -278.614378)
		(width 0.2032)
		(layer "F.Cu")
		(net "GND")
	)
	(segment
		(start 410.853382 -289.966654)
		(end 409.748482 -289.966654)
		(width 0.381)
		(layer "F.Cu")
		(net "GND")
	)
	(segment
		(start 342.773762 -271.289272)
		(end 342.774016 -271.289526)
		(width 0.2032)
		(layer "F.Cu")
		(net "GND")
	)
	(segment
		(start 124.907294 -279.428194)
		(end 124.907548 -279.964134)
		(width 0.2032)
		(layer "F.Cu")
		(net "GND")
	)
	(segment
		(start 275.268182 -228.766624)
		(end 274.163282 -228.766624)
		(width 0.381)
		(layer "F.Cu")
		(net "GND")
	)
	(segment
		(start 21.458428 -114.199416)
		(end 21.690838 -114.431826)
		(width 0.3556)
		(layer "F.Cu")
		(net "GND")
	)
	(segment
		(start 436.928514 -306.116736)
		(end 438.033414 -306.116736)
		(width 0.381)
		(layer "F.Cu")
		(net "GND")
	)
	(segment
		(start 86.265766 -242.830858)
		(end 86.265766 -242.294918)
		(width 0.2032)
		(layer "F.Cu")
		(net "GND")
	)
	(segment
		(start 347.473016 -269.661894)
		(end 347.473016 -270.19758)
		(width 0.2032)
		(layer "F.Cu")
		(net "GND")
	)
	(segment
		(start 14.579346 -265.316716)
		(end 15.684246 -265.316716)
		(width 0.381)
		(layer "F.Cu")
		(net "GND")
	)
	(segment
		(start 170.457114 -314.616592)
		(end 171.562014 -314.616592)
		(width 0.381)
		(layer "F.Cu")
		(net "GND")
	)
	(segment
		(start 214.615014 -266.1666)
		(end 215.719914 -266.1666)
		(width 0.381)
		(layer "F.Cu")
		(net "GND")
	)
	(segment
		(start 290.355782 -266.1666)
		(end 289.250882 -266.1666)
		(width 0.381)
		(layer "F.Cu")
		(net "GND")
	)
	(segment
		(start 176.896014 -294.216582)
		(end 178.000914 -294.216582)
		(width 0.381)
		(layer "F.Cu")
		(net "GND")
	)
	(segment
		(start 167.461946 -281.466798)
		(end 166.357046 -281.466798)
		(width 0.381)
		(layer "F.Cu")
		(net "GND")
	)
	(segment
		(start 208.176114 -288.266632)
		(end 209.281014 -288.266632)
		(width 0.381)
		(layer "F.Cu")
		(net "GND")
	)
	(segment
		(start 103.181912 -222.76181)
		(end 103.182166 -222.761556)
		(width 0.254)
		(layer "F.Cu")
		(net "GND")
	)
	(segment
		(start 175.005746 -260.21665)
		(end 173.900846 -260.21665)
		(width 0.381)
		(layer "F.Cu")
		(net "GND")
	)
	(segment
		(start 84.966048 -255.825498)
		(end 84.495894 -255.547622)
		(width 0.254)
		(layer "F.Cu")
		(net "GND")
	)
	(segment
		(start 100.942648 -264.500106)
		(end 100.942394 -264.50036)
		(width 0.254)
		(layer "F.Cu")
		(net "GND")
	)
	(segment
		(start 103.762048 -286.7533)
		(end 103.762048 -287.288986)
		(width 0.254)
		(layer "F.Cu")
		(net "GND")
	)
	(segment
		(start 345.95308 -232.250234)
		(end 345.95308 -231.714548)
		(width 0.2032)
		(layer "F.Cu")
		(net "GND")
	)
	(segment
		(start 215.719914 -238.116618)
		(end 216.824814 -238.116618)
		(width 0.381)
		(layer "F.Cu")
		(net "GND")
	)
	(segment
		(start 405.648414 -287.416748)
		(end 406.753314 -287.416748)
		(width 0.381)
		(layer "F.Cu")
		(net "GND")
	)
	(segment
		(start 200.632314 -282.316682)
		(end 201.737214 -282.316682)
		(width 0.381)
		(layer "F.Cu")
		(net "GND")
	)
	(segment
		(start 281.707082 -278.916638)
		(end 282.811982 -278.916638)
		(width 0.381)
		(layer "F.Cu")
		(net "GND")
	)
	(segment
		(start 305.443382 -264.466578)
		(end 306.548282 -264.466578)
		(width 0.381)
		(layer "F.Cu")
		(net "GND")
	)
	(segment
		(start 45.859446 -258.516628)
		(end 46.964346 -258.516628)
		(width 0.381)
		(layer "F.Cu")
		(net "GND")
	)
	(segment
		(start 175.755554 -116.175536)
		(end 175.355504 -116.575586)
		(width 0.3556)
		(layer "F.Cu")
		(net "GND")
	)
	(segment
		(start 127.616712 -226.553268)
		(end 127.616712 -226.017582)
		(width 0.254)
		(layer "F.Cu")
		(net "GND")
	)
	(segment
		(start 261.285482 -233.86669)
		(end 260.180582 -233.86669)
		(width 0.381)
		(layer "F.Cu")
		(net "GND")
	)
	(segment
		(start 340.250272 -44.711112)
		(end 340.318598 -44.642786)
		(width 0.2032)
		(layer "F.Cu")
		(net "GND")
	)
	(segment
		(start 204.076046 -236.416596)
		(end 205.180946 -236.416596)
		(width 0.381)
		(layer "F.Cu")
		(net "GND")
	)
	(segment
		(start 58.608214 -267.866622)
		(end 57.503314 -267.866622)
		(width 0.381)
		(layer "F.Cu")
		(net "GND")
	)
	(segment
		(start 57.503314 -245.76659)
		(end 58.608214 -245.76659)
		(width 0.381)
		(layer "F.Cu")
		(net "GND")
	)
	(segment
		(start 54.508146 -214.316564)
		(end 53.403246 -214.316564)
		(width 0.381)
		(layer "F.Cu")
		(net "GND")
	)
	(segment
		(start 34.871914 -200.716642)
		(end 35.976814 -200.716642)
		(width 0.381)
		(layer "F.Cu")
		(net "GND")
	)
	(segment
		(start 180.339746 -278.066754)
		(end 181.444646 -278.066754)
		(width 0.381)
		(layer "F.Cu")
		(net "GND")
	)
	(segment
		(start 369.558316 -272.103342)
		(end 369.558062 -272.639282)
		(width 0.2032)
		(layer "F.Cu")
		(net "GND")
	)
	(segment
		(start 60.947046 -244.916706)
		(end 62.051946 -244.916706)
		(width 0.381)
		(layer "F.Cu")
		(net "GND")
	)
	(segment
		(start 425.940982 -294.216582)
		(end 424.836082 -294.216582)
		(width 0.381)
		(layer "F.Cu")
		(net "GND")
	)
	(segment
		(start 63.942214 -301.01667)
		(end 65.047114 -301.01667)
		(width 0.381)
		(layer "F.Cu")
		(net "GND")
	)
	(segment
		(start 108.461048 -272.639028)
		(end 108.460794 -272.639282)
		(width 0.2032)
		(layer "F.Cu")
		(net "GND")
	)
	(segment
		(start 276.373082 -245.76659)
		(end 275.268182 -245.76659)
		(width 0.381)
		(layer "F.Cu")
		(net "GND")
	)
	(segment
		(start 297.899582 -278.916638)
		(end 299.004482 -278.916638)
		(width 0.381)
		(layer "F.Cu")
		(net "GND")
	)
	(segment
		(start 351.806764 -361.867704)
		(end 351.806764 -361.334812)
		(width 0.381)
		(layer "F.Cu")
		(net "GND")
	)
	(segment
		(start 197.20687 -111.117888)
		(end 197.41388 -111.324898)
		(width 0.3556)
		(layer "F.Cu")
		(net "GND")
	)
	(segment
		(start 200.632314 -271.266666)
		(end 201.737214 -271.266666)
		(width 0.381)
		(layer "F.Cu")
		(net "GND")
	)
	(segment
		(start 305.270154 -435.20741)
		(end 305.659282 -435.596538)
		(width 0.3556)
		(layer "F.Cu")
		(net "GND")
	)
	(segment
		(start 144.54632 -105.156508)
		(end 144.6022 -105.100628)
		(width 0.3556)
		(layer "F.Cu")
		(net "GND")
	)
	(segment
		(start 135.714994 -261.244842)
		(end 135.714994 -260.708902)
		(width 0.2032)
		(layer "F.Cu")
		(net "GND")
	)
	(segment
		(start 422.945814 -298.466764)
		(end 421.840914 -298.466764)
		(width 0.381)
		(layer "F.Cu")
		(net "GND")
	)
	(segment
		(start 266.619482 -221.116652)
		(end 267.724382 -221.116652)
		(width 0.381)
		(layer "F.Cu")
		(net "GND")
	)
	(segment
		(start 454.489312 -38.288976)
		(end 453.196452 -38.288976)
		(width 0.3556)
		(layer "F.Cu")
		(net "GND")
	)
	(segment
		(start 384.124962 -258.2672)
		(end 384.124962 -258.80314)
		(width 0.254)
		(layer "F.Cu")
		(net "GND")
	)
	(segment
		(start 459.559914 -210.916774)
		(end 458.455014 -210.916774)
		(width 0.381)
		(layer "F.Cu")
		(net "GND")
	)
	(segment
		(start 325.160894 -345.853258)
		(end 325.480172 -345.53398)
		(width 0.254)
		(layer "F.Cu")
		(net "GND")
	)
	(segment
		(start 52.298346 -279.766776)
		(end 53.403246 -279.766776)
		(width 0.381)
		(layer "F.Cu")
		(net "GND")
	)
	(segment
		(start 107.025186 -100.259388)
		(end 106.324908 -100.259388)
		(width 0.3556)
		(layer "F.Cu")
		(net "GND")
	)
	(segment
		(start 110.639098 -335.541112)
		(end 110.325154 -335.855056)
		(width 0.1778)
		(layer "F.Cu")
		(net "GND")
	)
	(segment
		(start 34.871914 -202.416664)
		(end 35.976814 -202.416664)
		(width 0.381)
		(layer "F.Cu")
		(net "GND")
	)
	(segment
		(start 263.624314 -265.316716)
		(end 264.729214 -265.316716)
		(width 0.381)
		(layer "F.Cu")
		(net "GND")
	)
	(segment
		(start 14.579346 -216.016586)
		(end 15.684246 -216.016586)
		(width 0.381)
		(layer "F.Cu")
		(net "GND")
	)
	(segment
		(start 110.340648 -275.35886)
		(end 110.340648 -275.894546)
		(width 0.254)
		(layer "F.Cu")
		(net "GND")
	)
	(segment
		(start 158.813246 -292.516814)
		(end 159.918146 -292.516814)
		(width 0.381)
		(layer "F.Cu")
		(net "GND")
	)
	(segment
		(start 382.135634 -228.1809)
		(end 382.135634 -227.64496)
		(width 0.2032)
		(layer "F.Cu")
		(net "GND")
	)
	(segment
		(start 46.493684 -391.089642)
		(end 47.21733 -391.089642)
		(width 0.4572)
		(layer "F.Cu")
		(net "GND")
	)
	(segment
		(start 91.074494 -272.917158)
		(end 91.074494 -273.452844)
		(width 0.2032)
		(layer "F.Cu")
		(net "GND")
	)
	(segment
		(start 199.527414 -267.866622)
		(end 200.632314 -267.866622)
		(width 0.381)
		(layer "F.Cu")
		(net "GND")
	)
	(segment
		(start 121.618248 -282.405582)
		(end 121.617994 -282.405836)
		(width 0.254)
		(layer "F.Cu")
		(net "GND")
	)
	(segment
		(start 138.894312 -239.57534)
		(end 139.086336 -239.57534)
		(width 0.254)
		(layer "F.Cu")
		(net "GND")
	)
	(segment
		(start 379.896116 -287.288986)
		(end 379.895862 -287.28924)
		(width 0.254)
		(layer "F.Cu")
		(net "GND")
	)
	(segment
		(start 301.343314 -267.016738)
		(end 302.448214 -267.016738)
		(width 0.3556)
		(layer "F.Cu")
		(net "GND")
	)
	(segment
		(start 179.105814 -297.616626)
		(end 178.000914 -297.616626)
		(width 0.381)
		(layer "F.Cu")
		(net "GND")
	)
	(segment
		(start 304.338482 -282.316682)
		(end 305.443382 -282.316682)
		(width 0.381)
		(layer "F.Cu")
		(net "GND")
	)
	(segment
		(start 373.787162 -266.405868)
		(end 373.787162 -266.941808)
		(width 0.2032)
		(layer "F.Cu")
		(net "GND")
	)
	(segment
		(start 42.415714 -247.466612)
		(end 41.310814 -247.466612)
		(width 0.381)
		(layer "F.Cu")
		(net "GND")
	)
	(segment
		(start 113.629694 -253.383796)
		(end 113.629694 -253.919736)
		(width 0.254)
		(layer "F.Cu")
		(net "GND")
	)
	(segment
		(start 194.193414 -264.466578)
		(end 193.088514 -264.466578)
		(width 0.381)
		(layer "F.Cu")
		(net "GND")
	)
	(segment
		(start 432.379882 -235.566712)
		(end 433.484782 -235.566712)
		(width 0.381)
		(layer "F.Cu")
		(net "GND")
	)
	(segment
		(start 368.03838 -222.76181)
		(end 368.038634 -222.761556)
		(width 0.254)
		(layer "F.Cu")
		(net "GND")
	)
	(segment
		(start 123.387866 -224.111566)
		(end 123.387866 -223.575626)
		(width 0.2032)
		(layer "F.Cu")
		(net "GND")
	)
	(segment
		(start 444.472314 -246.616728)
		(end 445.577214 -246.616728)
		(width 0.381)
		(layer "F.Cu")
		(net "GND")
	)
	(segment
		(start 336.085434 -236.319822)
		(end 336.085434 -235.783882)
		(width 0.254)
		(layer "F.Cu")
		(net "GND")
	)
	(segment
		(start 345.013534 -250.155964)
		(end 345.013534 -249.620024)
		(width 0.2032)
		(layer "F.Cu")
		(net "GND")
	)
	(segment
		(start 276.373082 -200.716642)
		(end 275.268182 -200.716642)
		(width 0.381)
		(layer "F.Cu")
		(net "GND")
	)
	(segment
		(start 24.081994 -129.583942)
		(end 24.368506 -129.870454)
		(width 0.381)
		(layer "F.Cu")
		(net "GND")
	)
	(segment
		(start 122.087894 -281.05608)
		(end 122.088148 -281.59202)
		(width 0.254)
		(layer "F.Cu")
		(net "GND")
	)
	(segment
		(start 278.711914 -244.916706)
		(end 279.816814 -244.916706)
		(width 0.381)
		(layer "F.Cu")
		(net "GND")
	)
	(segment
		(start 49.959514 -200.716642)
		(end 48.854614 -200.716642)
		(width 0.381)
		(layer "F.Cu")
		(net "GND")
	)
	(segment
		(start 281.707082 -204.116686)
		(end 282.811982 -204.116686)
		(width 0.381)
		(layer "F.Cu")
		(net "GND")
	)
	(segment
		(start 23.669752 -407.890218)
		(end 23.060152 -407.890218)
		(width 0.381)
		(layer "F.Cu")
		(net "GND")
	)
	(segment
		(start 59.842146 -267.016738)
		(end 60.947046 -267.016738)
		(width 0.381)
		(layer "F.Cu")
		(net "GND")
	)
	(segment
		(start 127.726694 -258.802886)
		(end 127.726948 -258.80314)
		(width 0.2032)
		(layer "F.Cu")
		(net "GND")
	)
	(segment
		(start 23.228046 -248.31675)
		(end 24.332946 -248.31675)
		(width 0.381)
		(layer "F.Cu")
		(net "GND")
	)
	(segment
		(start 303.923954 -32.462216)
		(end 303.923954 -33.472882)
		(width 0.3556)
		(layer "F.Cu")
		(net "GND")
	)
	(segment
		(start 442.698378 -43.620182)
		(end 443.888114 -43.620182)
		(width 0.3556)
		(layer "F.Cu")
		(net "GND")
	)
	(segment
		(start 187.883546 -289.11677)
		(end 188.988446 -289.11677)
		(width 0.381)
		(layer "F.Cu")
		(net "GND")
	)
	(segment
		(start 19.784314 -303.566576)
		(end 20.889214 -303.566576)
		(width 0.381)
		(layer "F.Cu")
		(net "GND")
	)
	(segment
		(start 31.147004 -7.215124)
		(end 31.147004 -8.320024)
		(width 0.3556)
		(layer "F.Cu")
		(net "GND")
	)
	(segment
		(start 279.816814 -304.416714)
		(end 278.711914 -304.416714)
		(width 0.381)
		(layer "F.Cu")
		(net "GND")
	)
	(segment
		(start 191.983614 -286.56661)
		(end 193.088514 -286.56661)
		(width 0.381)
		(layer "F.Cu")
		(net "GND")
	)
	(segment
		(start 167.461946 -225.36658)
		(end 166.357046 -225.36658)
		(width 0.381)
		(layer "F.Cu")
		(net "GND")
	)
	(segment
		(start 337.49488 -235.505752)
		(end 337.49488 -234.970066)
		(width 0.2032)
		(layer "F.Cu")
		(net "GND")
	)
	(segment
		(start 282.811982 -306.96662)
		(end 283.916882 -306.96662)
		(width 0.381)
		(layer "F.Cu")
		(net "GND")
	)
	(segment
		(start 424.58767 -51.22418)
		(end 423.95648 -51.22418)
		(width 0.3556)
		(layer "F.Cu")
		(net "GND")
	)
	(segment
		(start 48.60798 -171.473368)
		(end 49.17313 -171.473368)
		(width 0.3556)
		(layer "F.Cu")
		(net "GND")
	)
	(segment
		(start 419.643052 -133.114034)
		(end 420.282116 -133.114034)
		(width 0.381)
		(layer "F.Cu")
		(net "GND")
	)
	(segment
		(start 126.862332 -342.116156)
		(end 126.862332 -342.764872)
		(width 0.3556)
		(layer "F.Cu")
		(net "GND")
	)
	(segment
		(start 294.62222 -418.62756)
		(end 294.62222 -417.990528)
		(width 0.3556)
		(layer "F.Cu")
		(net "GND")
	)
	(segment
		(start 125.847094 -281.05608)
		(end 125.847348 -281.056334)
		(width 0.254)
		(layer "F.Cu")
		(net "GND")
	)
	(segment
		(start 91.904312 -216.250774)
		(end 91.904566 -216.25052)
		(width 0.254)
		(layer "F.Cu")
		(net "GND")
	)
	(segment
		(start 190.093346 -197.316598)
		(end 188.988446 -197.316598)
		(width 0.381)
		(layer "F.Cu")
		(net "GND")
	)
	(segment
		(start 335.725262 -265.592306)
		(end 335.725262 -266.128246)
		(width 0.2032)
		(layer "F.Cu")
		(net "GND")
	)
	(segment
		(start 344.073734 -238.761524)
		(end 344.07348 -238.76127)
		(width 0.2032)
		(layer "F.Cu")
		(net "GND")
	)
	(segment
		(start 57.503314 -235.566712)
		(end 56.195214 -235.566712)
		(width 0.381)
		(layer "F.Cu")
		(net "GND")
	)
	(segment
		(start 256.080514 -295.06672)
		(end 257.185414 -295.06672)
		(width 0.381)
		(layer "F.Cu")
		(net "GND")
	)
	(segment
		(start 197.637146 -300.166786)
		(end 196.532246 -300.166786)
		(width 0.381)
		(layer "F.Cu")
		(net "GND")
	)
	(segment
		(start 109.760512 -222.76181)
		(end 109.760766 -222.761556)
		(width 0.254)
		(layer "F.Cu")
		(net "GND")
	)
	(segment
		(start 256.080514 -225.36658)
		(end 257.185414 -225.36658)
		(width 0.381)
		(layer "F.Cu")
		(net "GND")
	)
	(segment
		(start 117.278912 -226.553268)
		(end 117.278912 -226.017582)
		(width 0.254)
		(layer "F.Cu")
		(net "GND")
	)
	(segment
		(start 26.63063 -125.368812)
		(end 25.92324 -125.368812)
		(width 0.3556)
		(layer "F.Cu")
		(net "GND")
	)
	(segment
		(start 436.928514 -270.416782)
		(end 438.033414 -270.416782)
		(width 0.381)
		(layer "F.Cu")
		(net "GND")
	)
	(segment
		(start 202.971146 -220.266768)
		(end 204.076046 -220.266768)
		(width 0.381)
		(layer "F.Cu")
		(net "GND")
	)
	(segment
		(start 281.707082 -205.816708)
		(end 282.811982 -205.816708)
		(width 0.381)
		(layer "F.Cu")
		(net "GND")
	)
	(segment
		(start 410.853382 -310.366664)
		(end 412.168848 -310.366664)
		(width 0.381)
		(layer "F.Cu")
		(net "GND")
	)
	(segment
		(start 181.444646 -268.71676)
		(end 182.549546 -268.71676)
		(width 0.381)
		(layer "F.Cu")
		(net "GND")
	)
	(segment
		(start 334.315562 -259.894832)
		(end 334.785462 -259.616956)
		(width 0.254)
		(layer "F.Cu")
		(net "GND")
	)
	(segment
		(start 293.799514 -217.716608)
		(end 292.694614 -217.716608)
		(width 0.381)
		(layer "F.Cu")
		(net "GND")
	)
	(segment
		(start 421.840914 -260.21665)
		(end 422.945814 -260.21665)
		(width 0.381)
		(layer "F.Cu")
		(net "GND")
	)
	(segment
		(start 457.221082 -216.866724)
		(end 456.116182 -216.866724)
		(width 0.381)
		(layer "F.Cu")
		(net "GND")
	)
	(segment
		(start 93.784166 -228.180646)
		(end 93.784166 -227.64496)
		(width 0.2032)
		(layer "F.Cu")
		(net "GND")
	)
	(segment
		(start 135.714994 -275.35886)
		(end 135.714994 -275.8948)
		(width 0.254)
		(layer "F.Cu")
		(net "GND")
	)
	(segment
		(start 123.387866 -230.086916)
		(end 123.387612 -230.086662)
		(width 0.254)
		(layer "F.Cu")
		(net "GND")
	)
	(segment
		(start 199.527414 -213.46668)
		(end 200.632314 -213.46668)
		(width 0.381)
		(layer "F.Cu")
		(net "GND")
	)
	(segment
		(start 385.424934 -242.017042)
		(end 384.485134 -241.481102)
		(width 0.254)
		(layer "F.Cu")
		(net "GND")
	)
	(segment
		(start 22.123146 -208.366614)
		(end 23.228046 -208.366614)
		(width 0.381)
		(layer "F.Cu")
		(net "GND")
	)
	(segment
		(start 297.899582 -219.41663)
		(end 299.004482 -219.41663)
		(width 0.381)
		(layer "F.Cu")
		(net "GND")
	)
	(segment
		(start 420.736014 -270.416782)
		(end 421.840914 -270.416782)
		(width 0.381)
		(layer "F.Cu")
		(net "GND")
	)
	(segment
		(start 374.257316 -278.614378)
		(end 374.257316 -279.150064)
		(width 0.254)
		(layer "F.Cu")
		(net "GND")
	)
	(segment
		(start 358.280716 -288.381186)
		(end 358.280716 -288.993326)
		(width 0.254)
		(layer "F.Cu")
		(net "GND")
	)
	(segment
		(start 304.338482 -294.216582)
		(end 305.443382 -294.216582)
		(width 0.381)
		(layer "F.Cu")
		(net "GND")
	)
	(segment
		(start 163.843462 -16.573754)
		(end 163.843462 -17.630394)
		(width 0.3556)
		(layer "F.Cu")
		(net "GND")
	)
	(segment
		(start 130.906266 -243.644928)
		(end 130.906012 -243.644674)
		(width 0.2032)
		(layer "F.Cu")
		(net "GND")
	)
	(segment
		(start 344.653362 -281.591766)
		(end 344.653616 -281.59202)
		(width 0.254)
		(layer "F.Cu")
		(net "GND")
	)
	(segment
		(start 296.794682 -272.966688)
		(end 297.899582 -272.966688)
		(width 0.381)
		(layer "F.Cu")
		(net "GND")
	)
	(segment
		(start 157.708346 -298.466764)
		(end 158.813246 -298.466764)
		(width 0.381)
		(layer "F.Cu")
		(net "GND")
	)
	(segment
		(start 290.355782 -222.816674)
		(end 291.460682 -222.816674)
		(width 0.381)
		(layer "F.Cu")
		(net "GND")
	)
	(segment
		(start 53.403246 -285.716726)
		(end 54.508146 -285.716726)
		(width 0.381)
		(layer "F.Cu")
		(net "GND")
	)
	(segment
		(start 425.940982 -200.716642)
		(end 427.045882 -200.716642)
		(width 0.381)
		(layer "F.Cu")
		(net "GND")
	)
	(segment
		(start 107.880912 -222.76181)
		(end 107.881166 -222.761556)
		(width 0.254)
		(layer "F.Cu")
		(net "GND")
	)
	(segment
		(start 26.223214 -306.96662)
		(end 27.328114 -306.96662)
		(width 0.381)
		(layer "F.Cu")
		(net "GND")
	)
	(segment
		(start 433.484782 -284.866588)
		(end 434.589682 -284.866588)
		(width 0.381)
		(layer "F.Cu")
		(net "GND")
	)
	(segment
		(start 457.221082 -262.76681)
		(end 456.116182 -262.76681)
		(width 0.381)
		(layer "F.Cu")
		(net "GND")
	)
	(segment
		(start 112.110266 -237.133892)
		(end 112.110266 -236.597698)
		(width 0.254)
		(layer "F.Cu")
		(net "GND")
	)
	(segment
		(start 170.457114 -247.466612)
		(end 171.562014 -247.466612)
		(width 0.381)
		(layer "F.Cu")
		(net "GND")
	)
	(segment
		(start 352.171762 -273.452844)
		(end 352.172016 -273.453098)
		(width 0.2032)
		(layer "F.Cu")
		(net "GND")
	)
	(segment
		(start 443.367414 -295.06672)
		(end 444.472314 -295.06672)
		(width 0.381)
		(layer "F.Cu")
		(net "GND")
	)
	(segment
		(start 309.313326 -436.216552)
		(end 309.313326 -436.66537)
		(width 0.3556)
		(layer "F.Cu")
		(net "GND")
	)
	(segment
		(start 115.869466 -232.250488)
		(end 115.869212 -232.250234)
		(width 0.2032)
		(layer "F.Cu")
		(net "GND")
	)
	(segment
		(start 92.967048 -97.105216)
		(end 93.145356 -96.926908)
		(width 0.3556)
		(layer "F.Cu")
		(net "GND")
	)
	(segment
		(start 311.882282 -233.86669)
		(end 312.987182 -233.86669)
		(width 0.381)
		(layer "F.Cu")
		(net "GND")
	)
	(segment
		(start 212.724746 -315.46673)
		(end 211.619846 -315.46673)
		(width 0.381)
		(layer "F.Cu")
		(net "GND")
	)
	(segment
		(start 122.917712 -249.342148)
		(end 122.917712 -248.806208)
		(width 0.2032)
		(layer "F.Cu")
		(net "GND")
	)
	(segment
		(start 95.303848 -272.103342)
		(end 95.303848 -272.639028)
		(width 0.2032)
		(layer "F.Cu")
		(net "GND")
	)
	(segment
		(start 382.135634 -236.319822)
		(end 382.135634 -235.783882)
		(width 0.2032)
		(layer "F.Cu")
		(net "GND")
	)
	(segment
		(start 8.140446 -251.716794)
		(end 7.035546 -251.716794)
		(width 0.381)
		(layer "F.Cu")
		(net "GND")
	)
	(segment
		(start 15.684246 -285.716726)
		(end 16.789146 -285.716726)
		(width 0.381)
		(layer "F.Cu")
		(net "GND")
	)
	(segment
		(start 262.519414 -231.316784)
		(end 263.624314 -231.316784)
		(width 0.381)
		(layer "F.Cu")
		(net "GND")
	)
	(segment
		(start 15.684246 -306.116736)
		(end 16.789146 -306.116736)
		(width 0.381)
		(layer "F.Cu")
		(net "GND")
	)
	(segment
		(start 308.887114 -296.766742)
		(end 307.782214 -296.766742)
		(width 0.381)
		(layer "F.Cu")
		(net "GND")
	)
	(segment
		(start 342.19134 -44.221146)
		(end 342.190578 -44.221146)
		(width 0.2032)
		(layer "F.Cu")
		(net "GND")
	)
	(segment
		(start 126.317248 -266.127992)
		(end 126.316994 -266.128246)
		(width 0.254)
		(layer "F.Cu")
		(net "GND")
	)
	(segment
		(start 178.000914 -210.066636)
		(end 179.105814 -210.066636)
		(width 0.381)
		(layer "F.Cu")
		(net "GND")
	)
	(segment
		(start 374.61698 -216.78646)
		(end 374.61698 -216.250774)
		(width 0.254)
		(layer "F.Cu")
		(net "GND")
	)
	(segment
		(start 365.844328 -336.592418)
		(end 366.32134 -336.115406)
		(width 0.2032)
		(layer "F.Cu")
		(net "GND")
	)
	(segment
		(start 158.813246 -231.316784)
		(end 157.708346 -231.316784)
		(width 0.381)
		(layer "F.Cu")
		(net "GND")
	)
	(segment
		(start 462.555082 -207.51673)
		(end 463.659982 -207.51673)
		(width 0.381)
		(layer "F.Cu")
		(net "GND")
	)
	(segment
		(start 19.784314 -267.866622)
		(end 18.679414 -267.866622)
		(width 0.381)
		(layer "F.Cu")
		(net "GND")
	)
	(segment
		(start 345.48318 -230.900478)
		(end 345.48318 -231.436418)
		(width 0.2032)
		(layer "F.Cu")
		(net "GND")
	)
	(segment
		(start 91.904312 -220.041978)
		(end 91.904566 -220.041724)
		(width 0.254)
		(layer "F.Cu")
		(net "GND")
	)
	(segment
		(start 42.415714 -262.76681)
		(end 41.310814 -262.76681)
		(width 0.381)
		(layer "F.Cu")
		(net "GND")
	)
	(segment
		(start 383.655062 -254.197612)
		(end 383.655062 -254.733552)
		(width 0.2032)
		(layer "F.Cu")
		(net "GND")
	)
	(segment
		(start 134.633462 -345.474036)
		(end 134.314184 -345.793314)
		(width 0.254)
		(layer "F.Cu")
		(net "GND")
	)
	(segment
		(start 128.086866 -227.367084)
		(end 128.086866 -226.831144)
		(width 0.2032)
		(layer "F.Cu")
		(net "GND")
	)
	(segment
		(start 339.84438 -216.78646)
		(end 339.84438 -216.250774)
		(width 0.254)
		(layer "F.Cu")
		(net "GND")
	)
	(segment
		(start 132.425694 -281.05608)
		(end 132.425694 -281.591512)
		(width 0.254)
		(layer "F.Cu")
		(net "GND")
	)
	(segment
		(start 66.2178 -55.540148)
		(end 66.2178 -54.524402)
		(width 0.3556)
		(layer "F.Cu")
		(net "GND")
	)
	(segment
		(start 460.664814 -244.916706)
		(end 459.559914 -244.916706)
		(width 0.381)
		(layer "F.Cu")
		(net "GND")
	)
	(segment
		(start 164.018214 -277.216616)
		(end 162.913314 -277.216616)
		(width 0.381)
		(layer "F.Cu")
		(net "GND")
	)
	(segment
		(start 97.543366 -249.341894)
		(end 97.543366 -248.806208)
		(width 0.2032)
		(layer "F.Cu")
		(net "GND")
	)
	(segment
		(start 294.904414 -206.666592)
		(end 293.799514 -206.666592)
		(width 0.381)
		(layer "F.Cu")
		(net "GND")
	)
	(segment
		(start 153.36393 -130.774948)
		(end 153.9748 -130.774948)
		(width 0.3556)
		(layer "F.Cu")
		(net "GND")
	)
	(segment
		(start 348.772734 -246.900446)
		(end 348.772734 -246.364506)
		(width 0.2032)
		(layer "F.Cu")
		(net "GND")
	)
	(segment
		(start 49.959514 -213.46668)
		(end 51.064414 -213.46668)
		(width 0.381)
		(layer "F.Cu")
		(net "GND")
	)
	(segment
		(start 351.702116 -263.96442)
		(end 351.702116 -264.500106)
		(width 0.254)
		(layer "F.Cu")
		(net "GND")
	)
	(segment
		(start 336.555334 -250.155964)
		(end 336.55508 -250.15571)
		(width 0.2032)
		(layer "F.Cu")
		(net "GND")
	)
	(segment
		(start 373.67718 -222.76181)
		(end 373.677434 -222.761556)
		(width 0.254)
		(layer "F.Cu")
		(net "GND")
	)
	(segment
		(start 366.15878 -216.78646)
		(end 366.15878 -216.250774)
		(width 0.254)
		(layer "F.Cu")
		(net "GND")
	)
	(segment
		(start 383.07518 -222.76181)
		(end 383.075434 -222.761556)
		(width 0.254)
		(layer "F.Cu")
		(net "GND")
	)
	(segment
		(start 420.282116 -137.178034)
		(end 419.590474 -137.178034)
		(width 0.381)
		(layer "F.Cu")
		(net "GND")
	)
	(segment
		(start 202.971146 -197.316598)
		(end 204.076046 -197.316598)
		(width 0.381)
		(layer "F.Cu")
		(net "GND")
	)
	(segment
		(start 304.122582 -207.51673)
		(end 305.443382 -207.51673)
		(width 0.381)
		(layer "F.Cu")
		(net "GND")
	)
	(segment
		(start 59.737244 -313.684158)
		(end 59.819794 -313.766708)
		(width 0.381)
		(layer "F.Cu")
		(net "GND")
	)
	(segment
		(start 443.35319 -29.575506)
		(end 443.35319 -30.362906)
		(width 0.17272)
		(layer "F.Cu")
		(net "GND")
	)
	(segment
		(start 352.172016 -266.406122)
		(end 352.172016 -266.941808)
		(width 0.2032)
		(layer "F.Cu")
		(net "GND")
	)
	(segment
		(start 63.942214 -250.866656)
		(end 65.047114 -250.866656)
		(width 0.381)
		(layer "F.Cu")
		(net "GND")
	)
	(segment
		(start 351.231962 -277.800562)
		(end 351.231962 -278.336248)
		(width 0.254)
		(layer "F.Cu")
		(net "GND")
	)
	(segment
		(start 187.883546 -317.166752)
		(end 188.988446 -317.166752)
		(width 0.381)
		(layer "F.Cu")
		(net "GND")
	)
	(segment
		(start 341.724234 -237.947454)
		(end 341.724234 -237.411514)
		(width 0.254)
		(layer "F.Cu")
		(net "GND")
	)
	(segment
		(start 99.422966 -237.947454)
		(end 99.422966 -237.411514)
		(width 0.254)
		(layer "F.Cu")
		(net "GND")
	)
	(segment
		(start 419.502082 -222.816674)
		(end 418.397182 -222.816674)
		(width 0.381)
		(layer "F.Cu")
		(net "GND")
	)
	(segment
		(start 49.959514 -301.01667)
		(end 51.064414 -301.01667)
		(width 0.381)
		(layer "F.Cu")
		(net "GND")
	)
	(segment
		(start 184.555638 -113.77549)
		(end 184.955688 -114.17554)
		(width 0.3556)
		(layer "F.Cu")
		(net "GND")
	)
	(segment
		(start 172.795946 -290.816792)
		(end 173.900846 -290.816792)
		(width 0.381)
		(layer "F.Cu")
		(net "GND")
	)
	(segment
		(start 428.279814 -315.46673)
		(end 429.384714 -315.46673)
		(width 0.381)
		(layer "F.Cu")
		(net "GND")
	)
	(segment
		(start 354.411534 -233.87812)
		(end 354.41128 -233.877866)
		(width 0.2032)
		(layer "F.Cu")
		(net "GND")
	)
	(segment
		(start 132.785612 -246.900192)
		(end 132.785612 -246.364506)
		(width 0.2032)
		(layer "F.Cu")
		(net "GND")
	)
	(segment
		(start 59.842146 -199.01662)
		(end 60.947046 -199.01662)
		(width 0.381)
		(layer "F.Cu")
		(net "GND")
	)
	(segment
		(start 464.764882 -312.91657)
		(end 463.659982 -312.91657)
		(width 0.381)
		(layer "F.Cu")
		(net "GND")
	)
	(segment
		(start 429.129952 -380.568962)
		(end 429.764952 -380.568962)
		(width 0.3556)
		(layer "F.Cu")
		(net "GND")
	)
	(segment
		(start 374.257316 -284.033468)
		(end 374.257062 -284.033722)
		(width 0.254)
		(layer "F.Cu")
		(net "GND")
	)
	(segment
		(start 159.737806 -236.397038)
		(end 160.121346 -236.397038)
		(width 0.381)
		(layer "F.Cu")
		(net "GND")
	)
	(segment
		(start 295.86682 -418.62756)
		(end 295.86682 -417.990528)
		(width 0.3556)
		(layer "F.Cu")
		(net "GND")
	)
	(segment
		(start 340.250272 -44.711112)
		(end 339.711538 -45.249846)
		(width 0.2032)
		(layer "F.Cu")
		(net "GND")
	)
	(segment
		(start 290.355782 -284.866588)
		(end 291.460682 -284.866588)
		(width 0.381)
		(layer "F.Cu")
		(net "GND")
	)
	(segment
		(start 136.654794 -285.125668)
		(end 136.654794 -285.661354)
		(width 0.2032)
		(layer "F.Cu")
		(net "GND")
	)
	(segment
		(start 428.279814 -244.916706)
		(end 429.384714 -244.916706)
		(width 0.381)
		(layer "F.Cu")
		(net "GND")
	)
	(segment
		(start 425.940982 -233.86669)
		(end 427.045882 -233.86669)
		(width 0.381)
		(layer "F.Cu")
		(net "GND")
	)
	(segment
		(start 149.01672 -35.794188)
		(end 148.19122 -36.619688)
		(width 0.3556)
		(layer "F.Cu")
		(net "GND")
	)
	(segment
		(start 46.496478 -390.007348)
		(end 47.21733 -390.007348)
		(width 0.4572)
		(layer "F.Cu")
		(net "GND")
	)
	(segment
		(start 375.557034 -236.319568)
		(end 375.557034 -235.783882)
		(width 0.2032)
		(layer "F.Cu")
		(net "GND")
	)
	(segment
		(start 450.56298 -111.308388)
		(end 450.737986 -111.133382)
		(width 0.3556)
		(layer "F.Cu")
		(net "GND")
	)
	(segment
		(start 410.853382 -282.316682)
		(end 409.748482 -282.316682)
		(width 0.381)
		(layer "F.Cu")
		(net "GND")
	)
	(segment
		(start 133.365494 -281.05608)
		(end 133.365494 -281.591512)
		(width 0.254)
		(layer "F.Cu")
		(net "GND")
	)
	(segment
		(start 19.784314 -299.316648)
		(end 20.889214 -299.316648)
		(width 0.381)
		(layer "F.Cu")
		(net "GND")
	)
	(segment
		(start 418.397182 -271.266666)
		(end 417.292282 -271.266666)
		(width 0.381)
		(layer "F.Cu")
		(net "GND")
	)
	(segment
		(start 212.724746 -203.266802)
		(end 211.619846 -203.266802)
		(width 0.381)
		(layer "F.Cu")
		(net "GND")
	)
	(segment
		(start 130.906012 -250.15571)
		(end 130.906012 -249.620024)
		(width 0.2032)
		(layer "F.Cu")
		(net "GND")
	)
	(segment
		(start 131.016248 -272.103342)
		(end 131.015994 -272.639282)
		(width 0.2032)
		(layer "F.Cu")
		(net "GND")
	)
	(segment
		(start 202.971146 -295.06672)
		(end 204.076046 -295.06672)
		(width 0.381)
		(layer "F.Cu")
		(net "GND")
	)
	(segment
		(start 122.448066 -228.99497)
		(end 122.447812 -228.994716)
		(width 0.254)
		(layer "F.Cu")
		(net "GND")
	)
	(segment
		(start 15.684246 -233.016806)
		(end 16.789146 -233.016806)
		(width 0.381)
		(layer "F.Cu")
		(net "GND")
	)
	(segment
		(start 29.666946 -267.016738)
		(end 30.771846 -267.016738)
		(width 0.381)
		(layer "F.Cu")
		(net "GND")
	)
	(segment
		(start 325.6534 -345.115896)
		(end 325.967598 -344.801698)
		(width 0.1778)
		(layer "F.Cu")
		(net "GND")
	)
	(segment
		(start 294.904414 -265.316716)
		(end 293.799514 -265.316716)
		(width 0.381)
		(layer "F.Cu")
		(net "GND")
	)
	(segment
		(start 190.093346 -292.516814)
		(end 188.988446 -292.516814)
		(width 0.381)
		(layer "F.Cu")
		(net "GND")
	)
	(segment
		(start 418.397182 -297.616626)
		(end 417.292282 -297.616626)
		(width 0.381)
		(layer "F.Cu")
		(net "GND")
	)
	(segment
		(start 193.088514 -299.316648)
		(end 194.193414 -299.316648)
		(width 0.381)
		(layer "F.Cu")
		(net "GND")
	)
	(segment
		(start 23.228046 -281.466798)
		(end 24.332946 -281.466798)
		(width 0.381)
		(layer "F.Cu")
		(net "GND")
	)
	(segment
		(start 135.714994 -270.475456)
		(end 135.714994 -271.011396)
		(width 0.254)
		(layer "F.Cu")
		(net "GND")
	)
	(segment
		(start 300.238414 -250.016772)
		(end 301.343314 -250.016772)
		(width 0.381)
		(layer "F.Cu")
		(net "GND")
	)
	(segment
		(start 199.527414 -312.91657)
		(end 200.632314 -312.91657)
		(width 0.381)
		(layer "F.Cu")
		(net "GND")
	)
	(segment
		(start 260.180582 -233.86669)
		(end 259.075682 -233.86669)
		(width 0.381)
		(layer "F.Cu")
		(net "GND")
	)
	(segment
		(start 157.708346 -300.166786)
		(end 158.813246 -300.166786)
		(width 0.381)
		(layer "F.Cu")
		(net "GND")
	)
	(segment
		(start 116.449094 -283.219652)
		(end 116.449348 -283.219906)
		(width 0.254)
		(layer "F.Cu")
		(net "GND")
	)
	(segment
		(start 110.230666 -242.017042)
		(end 110.230666 -241.48161)
		(width 0.254)
		(layer "F.Cu")
		(net "GND")
	)
	(segment
		(start 371.32768 -235.505752)
		(end 371.32768 -234.970066)
		(width 0.2032)
		(layer "F.Cu")
		(net "GND")
	)
	(segment
		(start 23.392384 -176.42967)
		(end 23.55215 -176.42967)
		(width 0.254)
		(layer "F.Cu")
		(net "GND")
	)
	(segment
		(start 29.977334 -170.029886)
		(end 29.977334 -169.400728)
		(width 0.381)
		(layer "F.Cu")
		(net "GND")
	)
	(segment
		(start 381.305562 -269.66164)
		(end 381.305562 -270.19758)
		(width 0.2032)
		(layer "F.Cu")
		(net "GND")
	)
	(segment
		(start 406.753314 -201.56678)
		(end 407.858214 -201.56678)
		(width 0.381)
		(layer "F.Cu")
		(net "GND")
	)
	(segment
		(start 165.252146 -261.916672)
		(end 166.357046 -261.916672)
		(width 0.381)
		(layer "F.Cu")
		(net "GND")
	)
	(segment
		(start 22.123146 -301.866808)
		(end 23.228046 -301.866808)
		(width 0.381)
		(layer "F.Cu")
		(net "GND")
	)
	(segment
		(start 101.412294 -268.033754)
		(end 101.412294 -268.569694)
		(width 0.2032)
		(layer "F.Cu")
		(net "GND")
	)
	(segment
		(start 96.133412 -243.644674)
		(end 96.133412 -243.108988)
		(width 0.2032)
		(layer "F.Cu")
		(net "GND")
	)
	(segment
		(start 366.15878 -216.250774)
		(end 366.159034 -216.25052)
		(width 0.254)
		(layer "F.Cu")
		(net "GND")
	)
	(segment
		(start 176.896014 -314.616592)
		(end 178.000914 -314.616592)
		(width 0.381)
		(layer "F.Cu")
		(net "GND")
	)
	(segment
		(start 45.859446 -220.266768)
		(end 46.964346 -220.266768)
		(width 0.381)
		(layer "F.Cu")
		(net "GND")
	)
	(segment
		(start 104.231694 -282.683966)
		(end 104.231694 -283.219906)
		(width 0.2032)
		(layer "F.Cu")
		(net "GND")
	)
	(segment
		(start 193.088514 -295.916604)
		(end 194.193414 -295.916604)
		(width 0.381)
		(layer "F.Cu")
		(net "GND")
	)
	(segment
		(start 448.572382 -198.166736)
		(end 447.467482 -198.166736)
		(width 0.381)
		(layer "F.Cu")
		(net "GND")
	)
	(segment
		(start 104.121712 -234.69219)
		(end 104.121966 -234.691936)
		(width 0.254)
		(layer "F.Cu")
		(net "GND")
	)
	(segment
		(start 416.056572 -182.579518)
		(end 415.624264 -182.579518)
		(width 0.2032)
		(layer "F.Cu")
		(net "GND")
	)
	(segment
		(start 136.655048 -277.522178)
		(end 136.654794 -277.522432)
		(width 0.254)
		(layer "F.Cu")
		(net "GND")
	)
	(segment
		(start 172.795946 -298.466764)
		(end 173.900846 -298.466764)
		(width 0.381)
		(layer "F.Cu")
		(net "GND")
	)
	(segment
		(start 379.31598 -247.714262)
		(end 379.31598 -247.178322)
		(width 0.2032)
		(layer "F.Cu")
		(net "GND")
	)
	(segment
		(start 356.401116 -270.475456)
		(end 356.401116 -271.011142)
		(width 0.2032)
		(layer "F.Cu")
		(net "GND")
	)
	(segment
		(start 338.787994 -59.778392)
		(end 338.90077 -59.665616)
		(width 0.2032)
		(layer "F.Cu")
		(net "GND")
	)
	(segment
		(start 333.398114 -39.443152)
		(end 333.89824 -39.295324)
		(width 0.2032)
		(layer "F.Cu")
		(net "GND")
	)
	(segment
		(start 337.025234 -220.041724)
		(end 337.025234 -219.506038)
		(width 0.254)
		(layer "F.Cu")
		(net "GND")
	)
	(segment
		(start 142.0622 -107.373928)
		(end 142.0622 -106.764328)
		(width 0.3556)
		(layer "F.Cu")
		(net "GND")
	)
	(segment
		(start 99.532694 -260.430518)
		(end 99.532948 -260.430772)
		(width 0.2032)
		(layer "F.Cu")
		(net "GND")
	)
	(segment
		(start 282.811982 -305.266598)
		(end 283.916882 -305.266598)
		(width 0.381)
		(layer "F.Cu")
		(net "GND")
	)
	(segment
		(start 254.975614 -306.116736)
		(end 256.080514 -306.116736)
		(width 0.381)
		(layer "F.Cu")
		(net "GND")
	)
	(segment
		(start 135.135112 -224.925382)
		(end 135.135112 -224.389442)
		(width 0.254)
		(layer "F.Cu")
		(net "GND")
	)
	(segment
		(start 35.976814 -289.966654)
		(end 34.871914 -289.966654)
		(width 0.381)
		(layer "F.Cu")
		(net "GND")
	)
	(segment
		(start 425.940982 -213.46668)
		(end 427.045882 -213.46668)
		(width 0.381)
		(layer "F.Cu")
		(net "GND")
	)
	(segment
		(start 89.555066 -245.27256)
		(end 89.554812 -245.272306)
		(width 0.2032)
		(layer "F.Cu")
		(net "GND")
	)
	(segment
		(start 285.150814 -289.11677)
		(end 286.255714 -289.11677)
		(width 0.381)
		(layer "F.Cu")
		(net "GND")
	)
	(segment
		(start 421.840914 -197.316598)
		(end 422.945814 -197.316598)
		(width 0.381)
		(layer "F.Cu")
		(net "GND")
	)
	(segment
		(start 339.954362 -264.778236)
		(end 339.954362 -265.314176)
		(width 0.2032)
		(layer "F.Cu")
		(net "GND")
	)
	(segment
		(start 104.231694 -272.917158)
		(end 104.231694 -273.452844)
		(width 0.2032)
		(layer "F.Cu")
		(net "GND")
	)
	(segment
		(start 39.420546 -260.21665)
		(end 38.315646 -260.21665)
		(width 0.381)
		(layer "F.Cu")
		(net "GND")
	)
	(segment
		(start 60.947046 -208.366614)
		(end 62.267846 -208.366614)
		(width 0.381)
		(layer "F.Cu")
		(net "GND")
	)
	(segment
		(start 303.634902 -55.054246)
		(end 303.634902 -54.012592)
		(width 0.508)
		(layer "F.Cu")
		(net "GND")
	)
	(segment
		(start 193.088514 -247.466612)
		(end 191.983614 -247.466612)
		(width 0.381)
		(layer "F.Cu")
		(net "GND")
	)
	(segment
		(start 127.726694 -263.68629)
		(end 127.726948 -263.686544)
		(width 0.2032)
		(layer "F.Cu")
		(net "GND")
	)
	(segment
		(start 105.312718 -338.702142)
		(end 105.15473 -338.86013)
		(width 0.381)
		(layer "F.Cu")
		(net "GND")
	)
	(segment
		(start 419.502082 -239.81664)
		(end 418.397182 -239.81664)
		(width 0.381)
		(layer "F.Cu")
		(net "GND")
	)
	(segment
		(start 256.080514 -287.416748)
		(end 257.185414 -287.416748)
		(width 0.381)
		(layer "F.Cu")
		(net "GND")
	)
	(segment
		(start 134.305294 -255.547368)
		(end 134.305548 -255.547622)
		(width 0.2032)
		(layer "F.Cu")
		(net "GND")
	)
	(segment
		(start 84.856066 -232.250488)
		(end 84.385912 -232.528364)
		(width 0.2032)
		(layer "F.Cu")
		(net "GND")
	)
	(segment
		(start 89.664794 -263.96442)
		(end 89.664794 -264.50036)
		(width 0.2032)
		(layer "F.Cu")
		(net "GND")
	)
	(segment
		(start 289.250882 -247.466612)
		(end 290.355782 -247.466612)
		(width 0.381)
		(layer "F.Cu")
		(net "GND")
	)
	(segment
		(start 158.813246 -225.36658)
		(end 159.918146 -225.36658)
		(width 0.381)
		(layer "F.Cu")
		(net "GND")
	)
	(segment
		(start 14.579346 -203.266802)
		(end 15.684246 -203.266802)
		(width 0.381)
		(layer "F.Cu")
		(net "GND")
	)
	(segment
		(start 267.724382 -277.216616)
		(end 268.829282 -277.216616)
		(width 0.381)
		(layer "F.Cu")
		(net "GND")
	)
	(segment
		(start 134.305294 -257.175254)
		(end 134.305294 -256.639314)
		(width 0.2032)
		(layer "F.Cu")
		(net "GND")
	)
	(segment
		(start 285.150814 -210.916774)
		(end 286.255714 -210.916774)
		(width 0.381)
		(layer "F.Cu")
		(net "GND")
	)
	(segment
		(start 122.448066 -237.133892)
		(end 122.448066 -236.597952)
		(width 0.2032)
		(layer "F.Cu")
		(net "GND")
	)
	(segment
		(start 26.223214 -216.866724)
		(end 27.328114 -216.866724)
		(width 0.381)
		(layer "F.Cu")
		(net "GND")
	)
	(segment
		(start 360.05008 -238.76127)
		(end 360.05008 -238.225584)
		(width 0.254)
		(layer "F.Cu")
		(net "GND")
	)
	(segment
		(start 413.192214 -201.56678)
		(end 414.297114 -201.56678)
		(width 0.381)
		(layer "F.Cu")
		(net "GND")
	)
	(segment
		(start 406.753314 -242.3668)
		(end 407.858214 -242.3668)
		(width 0.381)
		(layer "F.Cu")
		(net "GND")
	)
	(segment
		(start 95.663512 -247.178576)
		(end 95.663766 -247.178322)
		(width 0.2032)
		(layer "F.Cu")
		(net "GND")
	)
	(segment
		(start 275.268182 -210.066636)
		(end 276.373082 -210.066636)
		(width 0.381)
		(layer "F.Cu")
		(net "GND")
	)
	(segment
		(start 376.136916 -278.614378)
		(end 376.136662 -279.150318)
		(width 0.254)
		(layer "F.Cu")
		(net "GND")
	)
	(segment
		(start 296.578782 -219.41663)
		(end 297.899582 -219.41663)
		(width 0.381)
		(layer "F.Cu")
		(net "GND")
	)
	(segment
		(start 27.328114 -245.76659)
		(end 28.433014 -245.76659)
		(width 0.381)
		(layer "F.Cu")
		(net "GND")
	)
	(segment
		(start 202.971146 -248.31675)
		(end 204.076046 -248.31675)
		(width 0.381)
		(layer "F.Cu")
		(net "GND")
	)
	(segment
		(start 9.92886 -100.452428)
		(end 9.92886 -100.866448)
		(width 0.3556)
		(layer "F.Cu")
		(net "GND")
	)
	(segment
		(start 297.899582 -312.91657)
		(end 299.004482 -312.91657)
		(width 0.381)
		(layer "F.Cu")
		(net "GND")
	)
	(segment
		(start 113.46942 -97.137728)
		(end 113.269776 -97.337372)
		(width 0.3556)
		(layer "F.Cu")
		(net "GND")
	)
	(segment
		(start 20.024852 -60.999878)
		(end 21.790152 -60.999878)
		(width 0.3556)
		(layer "F.Cu")
		(net "GND")
	)
	(segment
		(start 220.785944 -106.384344)
		(end 220.500702 -106.384344)
		(width 0.3556)
		(layer "F.Cu")
		(net "GND")
	)
	(segment
		(start 432.379882 -316.316614)
		(end 433.484782 -316.316614)
		(width 0.381)
		(layer "F.Cu")
		(net "GND")
	)
	(segment
		(start 300.238414 -204.96657)
		(end 301.343314 -204.96657)
		(width 0.381)
		(layer "F.Cu")
		(net "GND")
	)
	(segment
		(start 52.298346 -296.766742)
		(end 53.403246 -296.766742)
		(width 0.381)
		(layer "F.Cu")
		(net "GND")
	)
	(segment
		(start 184.439814 -258.516628)
		(end 185.544714 -258.516628)
		(width 0.381)
		(layer "F.Cu")
		(net "GND")
	)
	(segment
		(start 337.495134 -223.57588)
		(end 337.495388 -223.575626)
		(width 0.254)
		(layer "F.Cu")
		(net "GND")
	)
	(segment
		(start 132.315712 -236.319822)
		(end 132.315712 -235.783882)
		(width 0.2032)
		(layer "F.Cu")
		(net "GND")
	)
	(segment
		(start 377.076716 -263.96442)
		(end 377.076716 -264.499852)
		(width 0.2032)
		(layer "F.Cu")
		(net "GND")
	)
	(segment
		(start 343.243916 -272.103342)
		(end 343.243916 -272.639028)
		(width 0.2032)
		(layer "F.Cu")
		(net "GND")
	)
	(segment
		(start 447.16192 -11.26998)
		(end 447.16319 -11.27125)
		(width 0.3556)
		(layer "F.Cu")
		(net "GND")
	)
	(segment
		(start 7.035546 -233.016806)
		(end 8.140446 -233.016806)
		(width 0.381)
		(layer "F.Cu")
		(net "GND")
	)
	(segment
		(start 138.424666 -246.900446)
		(end 139.482068 -246.900446)
		(width 0.2032)
		(layer "F.Cu")
		(net "GND")
	)
	(segment
		(start 79.75473 -59.772296)
		(end 79.75473 -60.381896)
		(width 0.4572)
		(layer "F.Cu")
		(net "GND")
	)
	(segment
		(start 435.823614 -307.816758)
		(end 436.928514 -307.816758)
		(width 0.381)
		(layer "F.Cu")
		(net "GND")
	)
	(segment
		(start 262.519414 -304.416714)
		(end 263.624314 -304.416714)
		(width 0.381)
		(layer "F.Cu")
		(net "GND")
	)
	(segment
		(start 34.871914 -312.91657)
		(end 35.976814 -312.91657)
		(width 0.381)
		(layer "F.Cu")
		(net "GND")
	)
	(segment
		(start 129.496566 -241.202972)
		(end 129.496566 -240.667286)
		(width 0.2032)
		(layer "F.Cu")
		(net "GND")
	)
	(segment
		(start 346.945966 -53.063648)
		(end 346.653358 -53.063648)
		(width 0.2032)
		(layer "F.Cu")
		(net "GND")
	)
	(segment
		(start 197.637146 -292.516814)
		(end 196.532246 -292.516814)
		(width 0.381)
		(layer "F.Cu")
		(net "GND")
	)
	(segment
		(start 59.842146 -278.066754)
		(end 60.947046 -278.066754)
		(width 0.381)
		(layer "F.Cu")
		(net "GND")
	)
	(segment
		(start 441.028582 -213.46668)
		(end 442.133482 -213.46668)
		(width 0.381)
		(layer "F.Cu")
		(net "GND")
	)
	(segment
		(start 138.064494 -281.05608)
		(end 138.064494 -281.59202)
		(width 0.13208)
		(layer "F.Cu")
		(net "GND")
	)
	(segment
		(start 34.871914 -207.51673)
		(end 35.976814 -207.51673)
		(width 0.381)
		(layer "F.Cu")
		(net "GND")
	)
	(segment
		(start 14.579346 -212.616796)
		(end 15.684246 -212.616796)
		(width 0.381)
		(layer "F.Cu")
		(net "GND")
	)
	(segment
		(start 95.193612 -240.388902)
		(end 95.193612 -239.853216)
		(width 0.2032)
		(layer "F.Cu")
		(net "GND")
	)
	(segment
		(start 125.847094 -268.033754)
		(end 125.847348 -268.569694)
		(width 0.2032)
		(layer "F.Cu")
		(net "GND")
	)
	(segment
		(start 96.133666 -232.250488)
		(end 96.133412 -232.250234)
		(width 0.2032)
		(layer "F.Cu")
		(net "GND")
	)
	(segment
		(start 57.503314 -310.366664)
		(end 58.608214 -310.366664)
		(width 0.381)
		(layer "F.Cu")
		(net "GND")
	)
	(segment
		(start 60.947046 -295.06672)
		(end 62.051946 -295.06672)
		(width 0.381)
		(layer "F.Cu")
		(net "GND")
	)
	(segment
		(start 433.484782 -232.166668)
		(end 434.589682 -232.166668)
		(width 0.381)
		(layer "F.Cu")
		(net "GND")
	)
	(segment
		(start 277.607014 -270.416782)
		(end 278.711914 -270.416782)
		(width 0.381)
		(layer "F.Cu")
		(net "GND")
	)
	(segment
		(start 306.421282 -239.81664)
		(end 305.443382 -239.81664)
		(width 0.381)
		(layer "F.Cu")
		(net "GND")
	)
	(segment
		(start 19.784314 -202.416664)
		(end 18.679414 -202.416664)
		(width 0.381)
		(layer "F.Cu")
		(net "GND")
	)
	(segment
		(start 352.641916 -276.986492)
		(end 352.641916 -277.521924)
		(width 0.2032)
		(layer "F.Cu")
		(net "GND")
	)
	(segment
		(start 261.285482 -250.866656)
		(end 260.180582 -250.866656)
		(width 0.381)
		(layer "F.Cu")
		(net "GND")
	)
	(segment
		(start 448.572382 -232.166668)
		(end 447.467482 -232.166668)
		(width 0.381)
		(layer "F.Cu")
		(net "GND")
	)
	(segment
		(start 214.615014 -294.216582)
		(end 215.719914 -294.216582)
		(width 0.381)
		(layer "F.Cu")
		(net "GND")
	)
	(segment
		(start 290.355782 -207.51673)
		(end 291.460682 -207.51673)
		(width 0.381)
		(layer "F.Cu")
		(net "GND")
	)
	(segment
		(start 123.027694 -277.800562)
		(end 123.027948 -278.336502)
		(width 0.2032)
		(layer "F.Cu")
		(net "GND")
	)
	(segment
		(start 171.562014 -282.316682)
		(end 170.457114 -282.316682)
		(width 0.381)
		(layer "F.Cu")
		(net "GND")
	)
	(segment
		(start 343.903046 -57.605168)
		(end 343.40292 -57.45734)
		(width 0.2032)
		(layer "F.Cu")
		(net "GND")
	)
	(segment
		(start 460.664814 -212.616796)
		(end 459.559914 -212.616796)
		(width 0.381)
		(layer "F.Cu")
		(net "GND")
	)
	(segment
		(start 368.618516 -282.405582)
		(end 368.618262 -282.405836)
		(width 0.254)
		(layer "F.Cu")
		(net "GND")
	)
	(segment
		(start 352.641916 -278.614378)
		(end 352.641916 -279.150064)
		(width 0.2032)
		(layer "F.Cu")
		(net "GND")
	)
	(segment
		(start 58.666888 -9.424924)
		(end 58.666888 -8.320024)
		(width 0.3556)
		(layer "F.Cu")
		(net "GND")
	)
	(segment
		(start 26.223214 -247.466612)
		(end 27.328114 -247.466612)
		(width 0.381)
		(layer "F.Cu")
		(net "GND")
	)
	(segment
		(start 328.244962 -40.218868)
		(end 328.244962 -39.946072)
		(width 0.2032)
		(layer "F.Cu")
		(net "GND")
	)
	(segment
		(start 279.364694 -19.929094)
		(end 280.050494 -19.929094)
		(width 0.3556)
		(layer "F.Cu")
		(net "GND")
	)
	(segment
		(start 131.016248 -267.755624)
		(end 131.015994 -267.755878)
		(width 0.254)
		(layer "F.Cu")
		(net "GND")
	)
	(segment
		(start 90.604848 -280.77795)
		(end 90.604594 -280.778204)
		(width 0.254)
		(layer "F.Cu")
		(net "GND")
	)
	(segment
		(start 341.833962 -255.011682)
		(end 341.833962 -255.547368)
		(width 0.2032)
		(layer "F.Cu")
		(net "GND")
	)
	(segment
		(start 93.314266 -214.344758)
		(end 93.314266 -213.732618)
		(width 0.254)
		(layer "F.Cu")
		(net "GND")
	)
	(segment
		(start 99.99853 -93.522546)
		(end 99.36353 -93.522546)
		(width 0.3556)
		(layer "F.Cu")
		(net "GND")
	)
	(segment
		(start 276.373082 -310.366664)
		(end 275.268182 -310.366664)
		(width 0.381)
		(layer "F.Cu")
		(net "GND")
	)
	(segment
		(start 126.676912 -237.411768)
		(end 126.677166 -237.411514)
		(width 0.254)
		(layer "F.Cu")
		(net "GND")
	)
	(segment
		(start 429.384714 -306.116736)
		(end 430.489614 -306.116736)
		(width 0.381)
		(layer "F.Cu")
		(net "GND")
	)
	(segment
		(start 116.449094 -279.428194)
		(end 116.449094 -279.96388)
		(width 0.254)
		(layer "F.Cu")
		(net "GND")
	)
	(segment
		(start 350.762316 -274.26666)
		(end 350.762062 -274.266914)
		(width 0.2032)
		(layer "F.Cu")
		(net "GND")
	)
	(segment
		(start 94.253812 -248.527824)
		(end 94.253812 -247.992138)
		(width 0.2032)
		(layer "F.Cu")
		(net "GND")
	)
	(segment
		(start 63.726314 -228.766624)
		(end 65.047114 -228.766624)
		(width 0.381)
		(layer "F.Cu")
		(net "GND")
	)
	(segment
		(start 27.328114 -275.516594)
		(end 28.433014 -275.516594)
		(width 0.381)
		(layer "F.Cu")
		(net "GND")
	)
	(segment
		(start 175.005746 -229.616762)
		(end 173.900846 -229.616762)
		(width 0.381)
		(layer "F.Cu")
		(net "GND")
	)
	(segment
		(start 297.899582 -306.96662)
		(end 299.004482 -306.96662)
		(width 0.381)
		(layer "F.Cu")
		(net "GND")
	)
	(segment
		(start 286.255714 -313.766708)
		(end 287.360614 -313.766708)
		(width 0.381)
		(layer "F.Cu")
		(net "GND")
	)
	(segment
		(start 289.250882 -215.166702)
		(end 290.355782 -215.166702)
		(width 0.381)
		(layer "F.Cu")
		(net "GND")
	)
	(segment
		(start 452.016114 -242.3668)
		(end 450.911214 -242.3668)
		(width 0.381)
		(layer "F.Cu")
		(net "GND")
	)
	(segment
		(start 300.238414 -267.016738)
		(end 301.343314 -267.016738)
		(width 0.3556)
		(layer "F.Cu")
		(net "GND")
	)
	(segment
		(start 118.218712 -229.808786)
		(end 118.218966 -229.808532)
		(width 0.254)
		(layer "F.Cu")
		(net "GND")
	)
	(segment
		(start 211.619846 -292.516814)
		(end 210.514946 -292.516814)
		(width 0.381)
		(layer "F.Cu")
		(net "GND")
	)
	(segment
		(start 202.971146 -301.866808)
		(end 204.076046 -301.866808)
		(width 0.381)
		(layer "F.Cu")
		(net "GND")
	)
	(segment
		(start 308.887114 -212.616796)
		(end 309.992014 -212.616796)
		(width 0.381)
		(layer "F.Cu")
		(net "GND")
	)
	(segment
		(start 279.816814 -195.616576)
		(end 278.711914 -195.616576)
		(width 0.381)
		(layer "F.Cu")
		(net "GND")
	)
	(segment
		(start 171.562014 -299.316648)
		(end 170.457114 -299.316648)
		(width 0.381)
		(layer "F.Cu")
		(net "GND")
	)
	(segment
		(start 15.684246 -279.766776)
		(end 16.789146 -279.766776)
		(width 0.381)
		(layer "F.Cu")
		(net "GND")
	)
	(segment
		(start 120.208294 -274.54479)
		(end 120.208548 -275.08073)
		(width 0.254)
		(layer "F.Cu")
		(net "GND")
	)
	(segment
		(start 286.255714 -263.616694)
		(end 287.360614 -263.616694)
		(width 0.381)
		(layer "F.Cu")
		(net "GND")
	)
	(segment
		(start 210.514946 -265.316716)
		(end 211.619846 -265.316716)
		(width 0.381)
		(layer "F.Cu")
		(net "GND")
	)
	(segment
		(start 444.472314 -304.416714)
		(end 445.577214 -304.416714)
		(width 0.381)
		(layer "F.Cu")
		(net "GND")
	)
	(segment
		(start 281.707082 -284.866588)
		(end 282.811982 -284.866588)
		(width 0.381)
		(layer "F.Cu")
		(net "GND")
	)
	(segment
		(start 57.503314 -222.816674)
		(end 56.398414 -222.816674)
		(width 0.381)
		(layer "F.Cu")
		(net "GND")
	)
	(segment
		(start 333.371952 -342.481662)
		(end 333.371952 -343.06002)
		(width 0.381)
		(layer "F.Cu")
		(net "GND")
	)
	(segment
		(start 92.844112 -234.69219)
		(end 92.844112 -234.156504)
		(width 0.254)
		(layer "F.Cu")
		(net "GND")
	)
	(segment
		(start 453.121014 -279.766776)
		(end 452.016114 -279.766776)
		(width 0.381)
		(layer "F.Cu")
		(net "GND")
	)
	(segment
		(start 53.842666 -116.134388)
		(end 53.233066 -116.134388)
		(width 0.3556)
		(layer "F.Cu")
		(net "GND")
	)
	(segment
		(start 60.947046 -296.766742)
		(end 62.051946 -296.766742)
		(width 0.381)
		(layer "F.Cu")
		(net "GND")
	)
	(segment
		(start 99.532694 -277.800562)
		(end 99.532694 -278.336248)
		(width 0.2032)
		(layer "F.Cu")
		(net "GND")
	)
	(segment
		(start 312.987182 -275.516594)
		(end 314.092082 -275.516594)
		(width 0.381)
		(layer "F.Cu")
		(net "GND")
	)
	(segment
		(start 456.116182 -295.916604)
		(end 455.011282 -295.916604)
		(width 0.381)
		(layer "F.Cu")
		(net "GND")
	)
	(segment
		(start 418.919914 -140.28674)
		(end 418.919914 -141.238478)
		(width 0.381)
		(layer "F.Cu")
		(net "GND")
	)
	(segment
		(start 48.854614 -262.76681)
		(end 49.959514 -262.76681)
		(width 0.381)
		(layer "F.Cu")
		(net "GND")
	)
	(segment
		(start 106.111294 -266.405868)
		(end 106.111294 -266.941808)
		(width 0.254)
		(layer "F.Cu")
		(net "GND")
	)
	(segment
		(start 378.846334 -245.27256)
		(end 378.84608 -245.272306)
		(width 0.2032)
		(layer "F.Cu")
		(net "GND")
	)
	(segment
		(start 275.268182 -205.816708)
		(end 274.163282 -205.816708)
		(width 0.381)
		(layer "F.Cu")
		(net "GND")
	)
	(segment
		(start 277.607014 -210.916774)
		(end 278.711914 -210.916774)
		(width 0.381)
		(layer "F.Cu")
		(net "GND")
	)
	(segment
		(start 60.947046 -272.116804)
		(end 62.051946 -272.116804)
		(width 0.381)
		(layer "F.Cu")
		(net "GND")
	)
	(segment
		(start 340.894162 -263.68629)
		(end 340.894416 -263.686544)
		(width 0.2032)
		(layer "F.Cu")
		(net "GND")
	)
	(segment
		(start 300.238414 -199.01662)
		(end 301.343314 -199.01662)
		(width 0.381)
		(layer "F.Cu")
		(net "GND")
	)
	(segment
		(start 107.991148 -268.034008)
		(end 107.991148 -268.569694)
		(width 0.254)
		(layer "F.Cu")
		(net "GND")
	)
	(segment
		(start 342.190578 -49.859946)
		(end 341.918798 -49.390046)
		(width 0.2032)
		(layer "F.Cu")
		(net "GND")
	)
	(segment
		(start 262.519414 -279.766776)
		(end 263.624314 -279.766776)
		(width 0.381)
		(layer "F.Cu")
		(net "GND")
	)
	(segment
		(start 51.064414 -294.216582)
		(end 49.959514 -294.216582)
		(width 0.381)
		(layer "F.Cu")
		(net "GND")
	)
	(segment
		(start 207.071214 -295.916604)
		(end 208.176114 -295.916604)
		(width 0.381)
		(layer "F.Cu")
		(net "GND")
	)
	(segment
		(start 262.519414 -313.766708)
		(end 263.624314 -313.766708)
		(width 0.381)
		(layer "F.Cu")
		(net "GND")
	)
	(segment
		(start 97.653094 -268.033754)
		(end 97.653348 -268.034008)
		(width 0.2032)
		(layer "F.Cu")
		(net "GND")
	)
	(segment
		(start 127.616712 -241.203226)
		(end 127.616966 -241.202972)
		(width 0.2032)
		(layer "F.Cu")
		(net "GND")
	)
	(segment
		(start 200.632314 -258.516628)
		(end 201.737214 -258.516628)
		(width 0.381)
		(layer "F.Cu")
		(net "GND")
	)
	(segment
		(start 214.615014 -239.81664)
		(end 215.719914 -239.81664)
		(width 0.381)
		(layer "F.Cu")
		(net "GND")
	)
	(segment
		(start 368.618516 -263.96442)
		(end 368.618516 -264.499852)
		(width 0.2032)
		(layer "F.Cu")
		(net "GND")
	)
	(segment
		(start 335.255362 -259.894832)
		(end 335.725262 -259.616956)
		(width 0.254)
		(layer "F.Cu")
		(net "GND")
	)
	(segment
		(start 435.823614 -216.016586)
		(end 436.928514 -216.016586)
		(width 0.381)
		(layer "F.Cu")
		(net "GND")
	)
	(segment
		(start 275.268182 -239.81664)
		(end 276.373082 -239.81664)
		(width 0.381)
		(layer "F.Cu")
		(net "GND")
	)
	(segment
		(start 114.459766 -216.78646)
		(end 114.459766 -216.25052)
		(width 0.254)
		(layer "F.Cu")
		(net "GND")
	)
	(segment
		(start 161.808414 -200.716642)
		(end 162.913314 -200.716642)
		(width 0.381)
		(layer "F.Cu")
		(net "GND")
	)
	(segment
		(start 208.176114 -194.766692)
		(end 209.281014 -194.766692)
		(width 0.381)
		(layer "F.Cu")
		(net "GND")
	)
	(segment
		(start 254.975614 -238.966756)
		(end 256.080514 -238.966756)
		(width 0.381)
		(layer "F.Cu")
		(net "GND")
	)
	(segment
		(start 93.893894 -269.66164)
		(end 93.894148 -269.661894)
		(width 0.2032)
		(layer "F.Cu")
		(net "GND")
	)
	(segment
		(start 122.978926 -122.496834)
		(end 122.978926 -123.112784)
		(width 0.3556)
		(layer "F.Cu")
		(net "GND")
	)
	(segment
		(start 173.900846 -300.166786)
		(end 175.005746 -300.166786)
		(width 0.381)
		(layer "F.Cu")
		(net "GND")
	)
	(segment
		(start 200.632314 -261.066788)
		(end 201.737214 -261.066788)
		(width 0.381)
		(layer "F.Cu")
		(net "GND")
	)
	(segment
		(start 311.882282 -224.516696)
		(end 312.987182 -224.516696)
		(width 0.381)
		(layer "F.Cu")
		(net "GND")
	)
	(segment
		(start 384.485134 -215.436958)
		(end 384.485388 -215.436704)
		(width 0.254)
		(layer "F.Cu")
		(net "GND")
	)
	(segment
		(start 199.527414 -264.466578)
		(end 200.632314 -264.466578)
		(width 0.381)
		(layer "F.Cu")
		(net "GND")
	)
	(segment
		(start 301.117 -24.612854)
		(end 303.123854 -22.606)
		(width 0.3556)
		(layer "F.Cu")
		(net "GND")
	)
	(segment
		(start 277.607014 -242.3668)
		(end 278.711914 -242.3668)
		(width 0.381)
		(layer "F.Cu")
		(net "GND")
	)
	(segment
		(start 344.07348 -242.016788)
		(end 344.07348 -241.481102)
		(width 0.2032)
		(layer "F.Cu")
		(net "GND")
	)
	(segment
		(start 373.207534 -250.155964)
		(end 373.207534 -249.620024)
		(width 0.2032)
		(layer "F.Cu")
		(net "GND")
	)
	(segment
		(start 60.947046 -270.416782)
		(end 62.051946 -270.416782)
		(width 0.381)
		(layer "F.Cu")
		(net "GND")
	)
	(segment
		(start 193.088514 -215.166702)
		(end 191.983614 -215.166702)
		(width 0.381)
		(layer "F.Cu")
		(net "GND")
	)
	(segment
		(start 429.384714 -223.666558)
		(end 430.489614 -223.666558)
		(width 0.381)
		(layer "F.Cu")
		(net "GND")
	)
	(segment
		(start 166.357046 -234.716574)
		(end 167.768016 -234.716574)
		(width 0.381)
		(layer "F.Cu")
		(net "GND")
	)
	(segment
		(start 245.311168 -89.143586)
		(end 245.311168 -90.202258)
		(width 0.3556)
		(layer "F.Cu")
		(net "GND")
	)
	(segment
		(start 345.593162 -268.033754)
		(end 345.593416 -268.034008)
		(width 0.2032)
		(layer "F.Cu")
		(net "GND")
	)
	(segment
		(start 23.7236 -71.821548)
		(end 23.0378 -71.821548)
		(width 0.3556)
		(layer "F.Cu")
		(net "GND")
	)
	(segment
		(start 18.679414 -264.466578)
		(end 19.784314 -264.466578)
		(width 0.381)
		(layer "F.Cu")
		(net "GND")
	)
	(segment
		(start 101.412294 -258.2672)
		(end 101.412294 -258.80314)
		(width 0.254)
		(layer "F.Cu")
		(net "GND")
	)
	(segment
		(start 439.923682 -205.816708)
		(end 441.028582 -205.816708)
		(width 0.381)
		(layer "F.Cu")
		(net "GND")
	)
	(segment
		(start 165.252146 -260.21665)
		(end 166.357046 -260.21665)
		(width 0.381)
		(layer "F.Cu")
		(net "GND")
	)
	(segment
		(start 170.457114 -284.866588)
		(end 169.352214 -284.866588)
		(width 0.381)
		(layer "F.Cu")
		(net "GND")
	)
	(segment
		(start 406.753314 -289.11677)
		(end 407.858214 -289.11677)
		(width 0.381)
		(layer "F.Cu")
		(net "GND")
	)
	(segment
		(start 86.845648 -275.35886)
		(end 86.37524 -275.08073)
		(width 0.2032)
		(layer "F.Cu")
		(net "GND")
	)
	(segment
		(start 267.724382 -230.466646)
		(end 268.829282 -230.466646)
		(width 0.381)
		(layer "F.Cu")
		(net "GND")
	)
	(segment
		(start 173.467014 -17.775428)
		(end 173.467014 -16.550132)
		(width 0.3556)
		(layer "F.Cu")
		(net "GND")
	)
	(segment
		(start 350.698054 -335.541112)
		(end 350.345756 -335.541112)
		(width 0.2032)
		(layer "F.Cu")
		(net "GND")
	)
	(segment
		(start 194.2719 -64.336168)
		(end 194.2719 -63.447168)
		(width 0.3556)
		(layer "F.Cu")
		(net "GND")
	)
	(segment
		(start 22.123146 -231.316784)
		(end 23.228046 -231.316784)
		(width 0.381)
		(layer "F.Cu")
		(net "GND")
	)
	(segment
		(start 425.940982 -267.866622)
		(end 427.045882 -267.866622)
		(width 0.381)
		(layer "F.Cu")
		(net "GND")
	)
	(segment
		(start 31.93415 -170.0276)
		(end 32.9184 -170.0276)
		(width 0.3556)
		(layer "F.Cu")
		(net "GND")
	)
	(segment
		(start 304.338482 -267.866622)
		(end 305.443382 -267.866622)
		(width 0.381)
		(layer "F.Cu")
		(net "GND")
	)
	(segment
		(start 57.503314 -269.566644)
		(end 58.608214 -269.566644)
		(width 0.381)
		(layer "F.Cu")
		(net "GND")
	)
	(segment
		(start 370.85778 -249.342148)
		(end 370.85778 -248.806208)
		(width 0.2032)
		(layer "F.Cu")
		(net "GND")
	)
	(segment
		(start 304.338482 -305.266598)
		(end 305.443382 -305.266598)
		(width 0.381)
		(layer "F.Cu")
		(net "GND")
	)
	(segment
		(start 135.605266 -246.900446)
		(end 136.075166 -247.178322)
		(width 0.254)
		(layer "F.Cu")
		(net "GND")
	)
	(segment
		(start 95.26778 -414.35528)
		(end 95.17126 -414.4518)
		(width 0.3556)
		(layer "F.Cu")
		(net "GND")
	)
	(segment
		(start 123.027694 -276.172676)
		(end 123.027948 -276.708616)
		(width 0.2032)
		(layer "F.Cu")
		(net "GND")
	)
	(segment
		(start 169.13606 -216.866724)
		(end 170.457114 -216.866724)
		(width 0.381)
		(layer "F.Cu")
		(net "GND")
	)
	(segment
		(start 428.279814 -220.266768)
		(end 429.384714 -220.266768)
		(width 0.381)
		(layer "F.Cu")
		(net "GND")
	)
	(segment
		(start 138.534648 -267.219938)
		(end 138.534394 -267.755878)
		(width 0.254)
		(layer "F.Cu")
		(net "GND")
	)
	(segment
		(start 100.472494 -255.547368)
		(end 100.472748 -255.547622)
		(width 0.2032)
		(layer "F.Cu")
		(net "GND")
	)
	(segment
		(start 376.496834 -220.041724)
		(end 376.496834 -219.506038)
		(width 0.254)
		(layer "F.Cu")
		(net "GND")
	)
	(segment
		(start 207.071214 -215.166702)
		(end 208.176114 -215.166702)
		(width 0.381)
		(layer "F.Cu")
		(net "GND")
	)
	(segment
		(start 348.772734 -237.133892)
		(end 348.772734 -236.598206)
		(width 0.254)
		(layer "F.Cu")
		(net "GND")
	)
	(segment
		(start 14.579346 -208.366614)
		(end 15.684246 -208.366614)
		(width 0.381)
		(layer "F.Cu")
		(net "GND")
	)
	(segment
		(start 336.195162 -272.917158)
		(end 336.195162 -273.453098)
		(width 0.2032)
		(layer "F.Cu")
		(net "GND")
	)
	(segment
		(start 342.304116 -270.475456)
		(end 342.304116 -271.011396)
		(width 0.2032)
		(layer "F.Cu")
		(net "GND")
	)
	(segment
		(start 19.784314 -204.116686)
		(end 18.679414 -204.116686)
		(width 0.381)
		(layer "F.Cu")
		(net "GND")
	)
	(segment
		(start 95.193866 -217.600276)
		(end 95.193866 -217.064336)
		(width 0.2032)
		(layer "F.Cu")
		(net "GND")
	)
	(segment
		(start 87.785194 -287.28924)
		(end 87.785194 -286.7533)
		(width 0.2032)
		(layer "F.Cu")
		(net "GND")
	)
	(segment
		(start 181.444646 -214.316564)
		(end 182.549546 -214.316564)
		(width 0.381)
		(layer "F.Cu")
		(net "GND")
	)
	(segment
		(start 347.472762 -276.708362)
		(end 347.473016 -276.708616)
		(width 0.2032)
		(layer "F.Cu")
		(net "GND")
	)
	(segment
		(start 275.268182 -312.91657)
		(end 274.163282 -312.91657)
		(width 0.381)
		(layer "F.Cu")
		(net "GND")
	)
	(segment
		(start 117.99316 -336.592418)
		(end 117.904514 -336.592418)
		(width 0.254)
		(layer "F.Cu")
		(net "GND")
	)
	(segment
		(start 342.773762 -281.05608)
		(end 342.773762 -281.59202)
		(width 0.254)
		(layer "F.Cu")
		(net "GND")
	)
	(segment
		(start 369.923822 -360.443272)
		(end 368.915188 -360.443272)
		(width 0.3556)
		(layer "F.Cu")
		(net "GND")
	)
	(segment
		(start 178.000914 -202.416664)
		(end 176.896014 -202.416664)
		(width 0.381)
		(layer "F.Cu")
		(net "GND")
	)
	(segment
		(start 366.15878 -226.553268)
		(end 366.15878 -226.017582)
		(width 0.254)
		(layer "F.Cu")
		(net "GND")
	)
	(segment
		(start 304.122582 -288.266632)
		(end 305.443382 -288.266632)
		(width 0.381)
		(layer "F.Cu")
		(net "GND")
	)
	(segment
		(start 346.063316 -256.361184)
		(end 346.063062 -256.361438)
		(width 0.2032)
		(layer "F.Cu")
		(net "GND")
	)
	(segment
		(start 11.135614 -272.966688)
		(end 12.240514 -272.966688)
		(width 0.381)
		(layer "F.Cu")
		(net "GND")
	)
	(segment
		(start 379.786134 -235.506006)
		(end 379.786134 -234.970066)
		(width 0.2032)
		(layer "F.Cu")
		(net "GND")
	)
	(segment
		(start 118.737126 -355.914452)
		(end 118.941088 -355.71049)
		(width 0.381)
		(layer "F.Cu")
		(net "GND")
	)
	(segment
		(start 347.363034 -249.341894)
		(end 347.363034 -248.806208)
		(width 0.2032)
		(layer "F.Cu")
		(net "GND")
	)
	(segment
		(start 27.131772 -407.33726)
		(end 26.496772 -407.33726)
		(width 0.3556)
		(layer "F.Cu")
		(net "GND")
	)
	(segment
		(start 441.028582 -264.466578)
		(end 442.133482 -264.466578)
		(width 0.381)
		(layer "F.Cu")
		(net "GND")
	)
	(segment
		(start 286.255714 -265.316716)
		(end 287.360614 -265.316716)
		(width 0.381)
		(layer "F.Cu")
		(net "GND")
	)
	(segment
		(start 366.32134 -336.115406)
		(end 366.32134 -335.886552)
		(width 0.2032)
		(layer "F.Cu")
		(net "GND")
	)
	(segment
		(start 429.384714 -311.216802)
		(end 430.489614 -311.216802)
		(width 0.381)
		(layer "F.Cu")
		(net "GND")
	)
	(segment
		(start 328.895964 -37.63518)
		(end 328.895964 -37.357558)
		(width 0.2032)
		(layer "F.Cu")
		(net "GND")
	)
	(segment
		(start 377.076716 -278.614378)
		(end 377.076462 -279.150318)
		(width 0.254)
		(layer "F.Cu")
		(net "GND")
	)
	(segment
		(start 347.214698 -39.03091)
		(end 346.799662 -39.445946)
		(width 0.2032)
		(layer "F.Cu")
		(net "GND")
	)
	(segment
		(start 96.603312 -226.017582)
		(end 96.603566 -226.017328)
		(width 0.254)
		(layer "F.Cu")
		(net "GND")
	)
	(segment
		(start 382.74244 -288.40811)
		(end 382.74244 -288.890202)
		(width 0.254)
		(layer "F.Cu")
		(net "GND")
	)
	(segment
		(start 400.24685 -8.320024)
		(end 400.24685 -9.424924)
		(width 0.3556)
		(layer "F.Cu")
		(net "GND")
	)
	(segment
		(start 42.415714 -278.916638)
		(end 41.310814 -278.916638)
		(width 0.381)
		(layer "F.Cu")
		(net "GND")
	)
	(segment
		(start 384.015234 -221.133924)
		(end 384.015234 -221.669864)
		(width 0.2032)
		(layer "F.Cu")
		(net "GND")
	)
	(segment
		(start 366.738916 -272.103342)
		(end 366.738662 -272.639282)
		(width 0.2032)
		(layer "F.Cu")
		(net "GND")
	)
	(segment
		(start 311.666382 -312.91657)
		(end 312.987182 -312.91657)
		(width 0.381)
		(layer "F.Cu")
		(net "GND")
	)
	(segment
		(start 382.605534 -220.855794)
		(end 382.605534 -220.320108)
		(width 0.2032)
		(layer "F.Cu")
		(net "GND")
	)
	(segment
		(start 22.123146 -315.46673)
		(end 23.228046 -315.46673)
		(width 0.381)
		(layer "F.Cu")
		(net "GND")
	)
	(segment
		(start 126.786894 -281.05608)
		(end 126.786894 -281.59202)
		(width 0.2032)
		(layer "F.Cu")
		(net "GND")
	)
	(segment
		(start 373.787162 -263.150604)
		(end 373.787162 -263.68629)
		(width 0.2032)
		(layer "F.Cu")
		(net "GND")
	)
	(segment
		(start 254.975614 -278.066754)
		(end 256.080514 -278.066754)
		(width 0.381)
		(layer "F.Cu")
		(net "GND")
	)
	(segment
		(start 272.273014 -229.616762)
		(end 271.168114 -229.616762)
		(width 0.381)
		(layer "F.Cu")
		(net "GND")
	)
	(segment
		(start 420.282116 -135.146034)
		(end 420.282116 -136.162034)
		(width 0.381)
		(layer "F.Cu")
		(net "GND")
	)
	(segment
		(start 122.558048 -273.730974)
		(end 122.557794 -274.266914)
		(width 0.2032)
		(layer "F.Cu")
		(net "GND")
	)
	(segment
		(start 331.881988 -56.438546)
		(end 332.422246 -56.438546)
		(width 0.2032)
		(layer "F.Cu")
		(net "GND")
	)
	(segment
		(start 202.322684 -105.715054)
		(end 201.279506 -105.715054)
		(width 0.3556)
		(layer "F.Cu")
		(net "GND")
	)
	(segment
		(start 428.279814 -195.616576)
		(end 429.384714 -195.616576)
		(width 0.381)
		(layer "F.Cu")
		(net "GND")
	)
	(segment
		(start 384.595116 -280.77795)
		(end 384.594862 -280.778204)
		(width 0.254)
		(layer "F.Cu")
		(net "GND")
	)
	(segment
		(start 195.427346 -223.666558)
		(end 196.532246 -223.666558)
		(width 0.381)
		(layer "F.Cu")
		(net "GND")
	)
	(segment
		(start 418.397182 -264.466578)
		(end 417.292282 -264.466578)
		(width 0.381)
		(layer "F.Cu")
		(net "GND")
	)
	(segment
		(start 93.783912 -237.947454)
		(end 93.784166 -237.947454)
		(width 0.254)
		(layer "F.Cu")
		(net "GND")
	)
	(segment
		(start 453.121014 -214.316564)
		(end 452.016114 -214.316564)
		(width 0.381)
		(layer "F.Cu")
		(net "GND")
	)
	(segment
		(start 170.457114 -308.666642)
		(end 171.562014 -308.666642)
		(width 0.381)
		(layer "F.Cu")
		(net "GND")
	)
	(segment
		(start 165.429184 -34.164524)
		(end 164.651944 -34.164524)
		(width 0.3556)
		(layer "F.Cu")
		(net "GND")
	)
	(segment
		(start 125.267466 -235.506006)
		(end 125.267466 -234.970066)
		(width 0.2032)
		(layer "F.Cu")
		(net "GND")
	)
	(segment
		(start 187.883546 -281.466798)
		(end 188.988446 -281.466798)
		(width 0.381)
		(layer "F.Cu")
		(net "GND")
	)
	(segment
		(start 357.6955 -406.583642)
		(end 357.6955 -407.233628)
		(width 0.3556)
		(layer "F.Cu")
		(net "GND")
	)
	(segment
		(start 308.887114 -225.36658)
		(end 309.992014 -225.36658)
		(width 0.381)
		(layer "F.Cu")
		(net "GND")
	)
	(segment
		(start 180.339746 -267.016738)
		(end 181.444646 -267.016738)
		(width 0.381)
		(layer "F.Cu")
		(net "GND")
	)
	(segment
		(start 263.624314 -234.716574)
		(end 264.729214 -234.716574)
		(width 0.381)
		(layer "F.Cu")
		(net "GND")
	)
	(segment
		(start 112.580166 -229.808532)
		(end 112.580166 -229.272846)
		(width 0.2032)
		(layer "F.Cu")
		(net "GND")
	)
	(segment
		(start 433.484782 -310.366664)
		(end 434.589682 -310.366664)
		(width 0.381)
		(layer "F.Cu")
		(net "GND")
	)
	(segment
		(start 164.018214 -196.466714)
		(end 162.913314 -196.466714)
		(width 0.381)
		(layer "F.Cu")
		(net "GND")
	)
	(segment
		(start 432.379882 -224.516696)
		(end 433.484782 -224.516696)
		(width 0.381)
		(layer "F.Cu")
		(net "GND")
	)
	(segment
		(start 94.833694 -263.150604)
		(end 94.833694 -263.686544)
		(width 0.2032)
		(layer "F.Cu")
		(net "GND")
	)
	(segment
		(start 194.193414 -202.416664)
		(end 193.088514 -202.416664)
		(width 0.381)
		(layer "F.Cu")
		(net "GND")
	)
	(segment
		(start 448.611752 -49.476406)
		(end 449.52666 -49.476406)
		(width 0.508)
		(layer "F.Cu")
		(net "GND")
	)
	(segment
		(start 117.278912 -216.250774)
		(end 117.279166 -216.25052)
		(width 0.254)
		(layer "F.Cu")
		(net "GND")
	)
	(segment
		(start 27.328114 -271.266666)
		(end 28.433014 -271.266666)
		(width 0.381)
		(layer "F.Cu")
		(net "GND")
	)
	(segment
		(start 173.900846 -201.56678)
		(end 172.795946 -201.56678)
		(width 0.381)
		(layer "F.Cu")
		(net "GND")
	)
	(segment
		(start 113.629694 -268.033754)
		(end 113.629694 -268.569694)
		(width 0.254)
		(layer "F.Cu")
		(net "GND")
	)
	(segment
		(start 15.684246 -234.716574)
		(end 16.789146 -234.716574)
		(width 0.381)
		(layer "F.Cu")
		(net "GND")
	)
	(segment
		(start 271.168114 -244.916706)
		(end 270.063214 -244.916706)
		(width 0.381)
		(layer "F.Cu")
		(net "GND")
	)
	(segment
		(start 51.467004 -8.320024)
		(end 51.467004 -7.215124)
		(width 0.3556)
		(layer "F.Cu")
		(net "GND")
	)
	(segment
		(start 366.72139 -338.70265)
		(end 366.72139 -339.339174)
		(width 0.381)
		(layer "F.Cu")
		(net "GND")
	)
	(segment
		(start 254.975614 -212.616796)
		(end 256.080514 -212.616796)
		(width 0.381)
		(layer "F.Cu")
		(net "GND")
	)
	(segment
		(start 51.064414 -314.616592)
		(end 49.959514 -314.616592)
		(width 0.381)
		(layer "F.Cu")
		(net "GND")
	)
	(segment
		(start 462.555082 -238.116618)
		(end 463.659982 -238.116618)
		(width 0.381)
		(layer "F.Cu")
		(net "GND")
	)
	(segment
		(start 204.076046 -233.016806)
		(end 205.180946 -233.016806)
		(width 0.381)
		(layer "F.Cu")
		(net "GND")
	)
	(segment
		(start 435.823614 -221.96679)
		(end 436.928514 -221.96679)
		(width 0.381)
		(layer "F.Cu")
		(net "GND")
	)
	(segment
		(start 63.942214 -233.86669)
		(end 65.047114 -233.86669)
		(width 0.381)
		(layer "F.Cu")
		(net "GND")
	)
	(segment
		(start 367.678716 -267.219938)
		(end 367.678462 -267.755878)
		(width 0.254)
		(layer "F.Cu")
		(net "GND")
	)
	(segment
		(start 381.229616 -97.204022)
		(end 381.8763 -97.204022)
		(width 0.3556)
		(layer "F.Cu")
		(net "GND")
	)
	(segment
		(start 432.379882 -284.866588)
		(end 433.484782 -284.866588)
		(width 0.381)
		(layer "F.Cu")
		(net "GND")
	)
	(segment
		(start 214.615014 -261.066788)
		(end 215.719914 -261.066788)
		(width 0.381)
		(layer "F.Cu")
		(net "GND")
	)
	(segment
		(start 126.207012 -246.900192)
		(end 126.207012 -246.364506)
		(width 0.2032)
		(layer "F.Cu")
		(net "GND")
	)
	(segment
		(start 423.804842 -390.616948)
		(end 423.195242 -390.616948)
		(width 0.3556)
		(layer "F.Cu")
		(net "GND")
	)
	(segment
		(start 345.48318 -229.808786)
		(end 345.483434 -229.808532)
		(width 0.2032)
		(layer "F.Cu")
		(net "GND")
	)
	(segment
		(start 34.871914 -299.316648)
		(end 33.767014 -299.316648)
		(width 0.381)
		(layer "F.Cu")
		(net "GND")
	)
	(segment
		(start 193.088514 -312.91657)
		(end 194.193414 -312.91657)
		(width 0.381)
		(layer "F.Cu")
		(net "GND")
	)
	(segment
		(start 162.913314 -239.81664)
		(end 164.018214 -239.81664)
		(width 0.381)
		(layer "F.Cu")
		(net "GND")
	)
	(segment
		(start 345.554554 -52.952396)
		(end 345.15171 -52.59324)
		(width 0.2032)
		(layer "F.Cu")
		(net "GND")
	)
	(segment
		(start 446.675002 -78.229968)
		(end 446.675002 -78.861412)
		(width 0.381)
		(layer "F.Cu")
		(net "GND")
	)
	(segment
		(start 184.439814 -245.76659)
		(end 185.544714 -245.76659)
		(width 0.381)
		(layer "F.Cu")
		(net "GND")
	)
	(segment
		(start 276.373082 -277.216616)
		(end 275.268182 -277.216616)
		(width 0.381)
		(layer "F.Cu")
		(net "GND")
	)
	(segment
		(start 266.619482 -222.816674)
		(end 267.724382 -222.816674)
		(width 0.381)
		(layer "F.Cu")
		(net "GND")
	)
	(segment
		(start 457.221082 -282.316682)
		(end 456.116182 -282.316682)
		(width 0.381)
		(layer "F.Cu")
		(net "GND")
	)
	(segment
		(start 300.238414 -195.616576)
		(end 301.343314 -195.616576)
		(width 0.381)
		(layer "F.Cu")
		(net "GND")
	)
	(segment
		(start 441.028582 -267.866622)
		(end 442.133482 -267.866622)
		(width 0.381)
		(layer "F.Cu")
		(net "GND")
	)
	(segment
		(start 121.977912 -222.76181)
		(end 121.978166 -222.761556)
		(width 0.254)
		(layer "F.Cu")
		(net "GND")
	)
	(segment
		(start 414.297114 -263.616694)
		(end 415.402014 -263.616694)
		(width 0.381)
		(layer "F.Cu")
		(net "GND")
	)
	(segment
		(start 445.577214 -201.56678)
		(end 444.472314 -201.56678)
		(width 0.381)
		(layer "F.Cu")
		(net "GND")
	)
	(segment
		(start 262.519414 -289.11677)
		(end 263.624314 -289.11677)
		(width 0.381)
		(layer "F.Cu")
		(net "GND")
	)
	(segment
		(start 101.874574 -95.47352)
		(end 102.509574 -95.47352)
		(width 0.3556)
		(layer "F.Cu")
		(net "GND")
	)
	(segment
		(start 429.384714 -248.31675)
		(end 430.489614 -248.31675)
		(width 0.381)
		(layer "F.Cu")
		(net "GND")
	)
	(segment
		(start 403.846792 -11.26998)
		(end 403.846792 -12.37488)
		(width 0.3556)
		(layer "F.Cu")
		(net "GND")
	)
	(segment
		(start 278.711914 -260.21665)
		(end 279.816814 -260.21665)
		(width 0.381)
		(layer "F.Cu")
		(net "GND")
	)
	(segment
		(start 348.772734 -220.855794)
		(end 348.772734 -220.319854)
		(width 0.2032)
		(layer "F.Cu")
		(net "GND")
	)
	(segment
		(start 278.711914 -267.016738)
		(end 279.816814 -267.016738)
		(width 0.381)
		(layer "F.Cu")
		(net "GND")
	)
	(segment
		(start 425.940982 -308.666642)
		(end 424.836082 -308.666642)
		(width 0.381)
		(layer "F.Cu")
		(net "GND")
	)
	(segment
		(start 43.520614 -297.616626)
		(end 42.415714 -297.616626)
		(width 0.381)
		(layer "F.Cu")
		(net "GND")
	)
	(segment
		(start 92.844112 -220.041978)
		(end 92.844366 -220.041724)
		(width 0.254)
		(layer "F.Cu")
		(net "GND")
	)
	(segment
		(start 294.904414 -278.066754)
		(end 293.799514 -278.066754)
		(width 0.381)
		(layer "F.Cu")
		(net "GND")
	)
	(segment
		(start 121.508266 -227.367084)
		(end 121.508266 -226.831144)
		(width 0.2032)
		(layer "F.Cu")
		(net "GND")
	)
	(segment
		(start 21.577046 -98.171508)
		(end 22.23008 -98.171508)
		(width 0.3556)
		(layer "F.Cu")
		(net "GND")
	)
	(segment
		(start 181.444646 -227.066602)
		(end 182.549546 -227.066602)
		(width 0.381)
		(layer "F.Cu")
		(net "GND")
	)
	(segment
		(start 344.903552 -37.056822)
		(end 344.903552 -37.63518)
		(width 0.2032)
		(layer "F.Cu")
		(net "GND")
	)
	(segment
		(start 436.928514 -279.766776)
		(end 438.033414 -279.766776)
		(width 0.381)
		(layer "F.Cu")
		(net "GND")
	)
	(segment
		(start 419.502082 -308.666642)
		(end 418.397182 -308.666642)
		(width 0.381)
		(layer "F.Cu")
		(net "GND")
	)
	(segment
		(start 39.420546 -301.866808)
		(end 38.315646 -301.866808)
		(width 0.381)
		(layer "F.Cu")
		(net "GND")
	)
	(segment
		(start 367.568734 -224.111566)
		(end 367.568734 -223.575626)
		(width 0.2032)
		(layer "F.Cu")
		(net "GND")
	)
	(segment
		(start 170.457114 -291.666676)
		(end 171.869608 -291.666676)
		(width 0.381)
		(layer "F.Cu")
		(net "GND")
	)
	(segment
		(start 333.23657 -54.089046)
		(end 334.05064 -53.619146)
		(width 0.2032)
		(layer "F.Cu")
		(net "GND")
	)
	(segment
		(start 300.238414 -301.866808)
		(end 301.343314 -301.866808)
		(width 0.381)
		(layer "F.Cu")
		(net "GND")
	)
	(segment
		(start 354.411534 -227.367084)
		(end 354.411534 -226.831144)
		(width 0.2032)
		(layer "F.Cu")
		(net "GND")
	)
	(segment
		(start 297.899582 -272.966688)
		(end 299.004482 -272.966688)
		(width 0.381)
		(layer "F.Cu")
		(net "GND")
	)
	(segment
		(start 20.346924 -8.320024)
		(end 20.346924 -9.424924)
		(width 0.3556)
		(layer "F.Cu")
		(net "GND")
	)
	(segment
		(start 353.94138 -223.297496)
		(end 353.94138 -222.76181)
		(width 0.254)
		(layer "F.Cu")
		(net "GND")
	)
	(segment
		(start 340.894416 -271.289526)
		(end 340.894416 -271.825212)
		(width 0.2032)
		(layer "F.Cu")
		(net "GND")
	)
	(segment
		(start 382.642364 -345.316302)
		(end 382.642364 -345.121484)
		(width 0.2032)
		(layer "F.Cu")
		(net "GND")
	)
	(segment
		(start 392.563858 -39.61257)
		(end 392.563858 -38.829742)
		(width 0.3556)
		(layer "F.Cu")
		(net "GND")
	)
	(segment
		(start 126.676912 -237.947454)
		(end 126.676912 -237.411768)
		(width 0.254)
		(layer "F.Cu")
		(net "GND")
	)
	(segment
		(start 169.352214 -211.766658)
		(end 170.457114 -211.766658)
		(width 0.381)
		(layer "F.Cu")
		(net "GND")
	)
	(segment
		(start 414.297114 -214.316564)
		(end 415.402014 -214.316564)
		(width 0.381)
		(layer "F.Cu")
		(net "GND")
	)
	(segment
		(start 171.562014 -241.516662)
		(end 170.457114 -241.516662)
		(width 0.381)
		(layer "F.Cu")
		(net "GND")
	)
	(segment
		(start 127.69596 -98.61042)
		(end 127.69596 -99.68484)
		(width 0.254)
		(layer "F.Cu")
		(net "GND")
	)
	(segment
		(start 188.988446 -272.116804)
		(end 190.093346 -272.116804)
		(width 0.381)
		(layer "F.Cu")
		(net "GND")
	)
	(segment
		(start 256.080514 -258.516628)
		(end 257.185414 -258.516628)
		(width 0.381)
		(layer "F.Cu")
		(net "GND")
	)
	(segment
		(start 281.707082 -286.56661)
		(end 282.811982 -286.56661)
		(width 0.381)
		(layer "F.Cu")
		(net "GND")
	)
	(segment
		(start 303.875186 -425.00931)
		(end 303.875186 -424.585892)
		(width 0.3556)
		(layer "F.Cu")
		(net "GND")
	)
	(segment
		(start 58.608214 -250.866656)
		(end 57.503314 -250.866656)
		(width 0.381)
		(layer "F.Cu")
		(net "GND")
	)
	(segment
		(start 28.978098 -71.88073)
		(end 28.978098 -72.51573)
		(width 0.3556)
		(layer "F.Cu")
		(net "GND")
	)
	(segment
		(start 406.753314 -197.316598)
		(end 407.858214 -197.316598)
		(width 0.381)
		(layer "F.Cu")
		(net "GND")
	)
	(segment
		(start 344.54338 -222.76181)
		(end 344.543634 -222.761556)
		(width 0.254)
		(layer "F.Cu")
		(net "GND")
	)
	(segment
		(start 182.549546 -283.166566)
		(end 181.444646 -283.166566)
		(width 0.381)
		(layer "F.Cu")
		(net "GND")
	)
	(segment
		(start 288.418016 -367.919508)
		(end 287.894776 -367.919508)
		(width 0.381)
		(layer "F.Cu")
		(net "GND")
	)
	(segment
		(start 102.135686 -335.79181)
		(end 102.135686 -336.040222)
		(width 0.1778)
		(layer "F.Cu")
		(net "GND")
	)
	(segment
		(start 307.782214 -214.316564)
		(end 308.887114 -214.316564)
		(width 0.381)
		(layer "F.Cu")
		(net "GND")
	)
	(segment
		(start 11.135614 -241.516662)
		(end 12.240514 -241.516662)
		(width 0.381)
		(layer "F.Cu")
		(net "GND")
	)
	(segment
		(start 367.568734 -217.600276)
		(end 367.568734 -217.064336)
		(width 0.254)
		(layer "F.Cu")
		(net "GND")
	)
	(segment
		(start 458.455014 -313.766708)
		(end 459.559914 -313.766708)
		(width 0.381)
		(layer "F.Cu")
		(net "GND")
	)
	(segment
		(start 355.461316 -266.127992)
		(end 355.461062 -266.128246)
		(width 0.2032)
		(layer "F.Cu")
		(net "GND")
	)
	(segment
		(start 45.859446 -199.01662)
		(end 46.964346 -199.01662)
		(width 0.381)
		(layer "F.Cu")
		(net "GND")
	)
	(segment
		(start 369.558316 -273.730974)
		(end 369.558316 -274.266914)
		(width 0.2032)
		(layer "F.Cu")
		(net "GND")
	)
	(segment
		(start 53.403246 -203.266802)
		(end 52.298346 -203.266802)
		(width 0.381)
		(layer "F.Cu")
		(net "GND")
	)
	(segment
		(start 460.664814 -203.266802)
		(end 459.559914 -203.266802)
		(width 0.381)
		(layer "F.Cu")
		(net "GND")
	)
	(segment
		(start 340.78418 -242.830858)
		(end 340.78418 -242.295172)
		(width 0.2032)
		(layer "F.Cu")
		(net "GND")
	)
	(segment
		(start 460.664814 -242.3668)
		(end 459.559914 -242.3668)
		(width 0.381)
		(layer "F.Cu")
		(net "GND")
	)
	(segment
		(start 277.607014 -204.96657)
		(end 278.711914 -204.96657)
		(width 0.381)
		(layer "F.Cu")
		(net "GND")
	)
	(segment
		(start 89.555066 -240.389156)
		(end 89.554812 -240.388902)
		(width 0.2032)
		(layer "F.Cu")
		(net "GND")
	)
	(segment
		(start 338.90458 -230.900478)
		(end 338.90458 -231.436418)
		(width 0.2032)
		(layer "F.Cu")
		(net "GND")
	)
	(segment
		(start 28.433014 -196.466714)
		(end 27.328114 -196.466714)
		(width 0.381)
		(layer "F.Cu")
		(net "GND")
	)
	(segment
		(start 463.659982 -235.566712)
		(end 464.764882 -235.566712)
		(width 0.381)
		(layer "F.Cu")
		(net "GND")
	)
	(segment
		(start 114.660934 -110.236762)
		(end 114.660934 -109.106462)
		(width 0.3556)
		(layer "F.Cu")
		(net "GND")
	)
	(segment
		(start 176.896014 -288.266632)
		(end 178.000914 -288.266632)
		(width 0.381)
		(layer "F.Cu")
		(net "GND")
	)
	(segment
		(start 93.893894 -265.313922)
		(end 93.894148 -265.314176)
		(width 0.2032)
		(layer "F.Cu")
		(net "GND")
	)
	(segment
		(start 431.609754 -134.494778)
		(end 431.000154 -134.494778)
		(width 0.381)
		(layer "F.Cu")
		(net "GND")
	)
	(segment
		(start 371.327934 -220.855794)
		(end 371.327934 -220.319854)
		(width 0.2032)
		(layer "F.Cu")
		(net "GND")
	)
	(segment
		(start 255.261618 -49.366424)
		(end 256.049018 -49.366424)
		(width 0.17272)
		(layer "F.Cu")
		(net "GND")
	)
	(segment
		(start 22.123146 -244.916706)
		(end 23.228046 -244.916706)
		(width 0.381)
		(layer "F.Cu")
		(net "GND")
	)
	(segment
		(start 19.790664 -109.859826)
		(end 19.17446 -109.859826)
		(width 0.3556)
		(layer "F.Cu")
		(net "GND")
	)
	(segment
		(start 176.896014 -230.466646)
		(end 178.000914 -230.466646)
		(width 0.381)
		(layer "F.Cu")
		(net "GND")
	)
	(segment
		(start 52.298346 -229.616762)
		(end 53.403246 -229.616762)
		(width 0.381)
		(layer "F.Cu")
		(net "GND")
	)
	(segment
		(start 376.606562 -269.66164)
		(end 376.606816 -270.167862)
		(width 0.2032)
		(layer "F.Cu")
		(net "GND")
	)
	(segment
		(start 342.735154 -54.558692)
		(end 342.844374 -54.747668)
		(width 0.2032)
		(layer "F.Cu")
		(net "GND")
	)
	(segment
		(start 193.35623 -43.849544)
		(end 192.55994 -43.849544)
		(width 0.3556)
		(layer "F.Cu")
		(net "GND")
	)
	(segment
		(start 459.559914 -197.316598)
		(end 458.455014 -197.316598)
		(width 0.381)
		(layer "F.Cu")
		(net "GND")
	)
	(segment
		(start 11.135614 -277.216616)
		(end 12.240514 -277.216616)
		(width 0.381)
		(layer "F.Cu")
		(net "GND")
	)
	(segment
		(start 428.279814 -242.3668)
		(end 429.384714 -242.3668)
		(width 0.381)
		(layer "F.Cu")
		(net "GND")
	)
	(segment
		(start 53.267102 -11.26998)
		(end 53.267102 -10.16508)
		(width 0.3556)
		(layer "F.Cu")
		(net "GND")
	)
	(segment
		(start 38.315646 -221.96679)
		(end 37.210746 -221.96679)
		(width 0.381)
		(layer "F.Cu")
		(net "GND")
	)
	(segment
		(start 20.889214 -224.516696)
		(end 19.784314 -224.516696)
		(width 0.381)
		(layer "F.Cu")
		(net "GND")
	)
	(segment
		(start 378.016516 -286.7533)
		(end 378.016516 -287.288986)
		(width 0.254)
		(layer "F.Cu")
		(net "GND")
	)
	(segment
		(start 194.193414 -239.81664)
		(end 193.088514 -239.81664)
		(width 0.381)
		(layer "F.Cu")
		(net "GND")
	)
	(segment
		(start 380.835916 -256.361184)
		(end 380.835662 -256.361438)
		(width 0.254)
		(layer "F.Cu")
		(net "GND")
	)
	(segment
		(start 380.725934 -243.644928)
		(end 380.725934 -243.108988)
		(width 0.2032)
		(layer "F.Cu")
		(net "GND")
	)
	(segment
		(start 345.15171 -49.59096)
		(end 345.554554 -48.950372)
		(width 0.1778)
		(layer "F.Cu")
		(net "GND")
	)
	(segment
		(start 436.928514 -260.21665)
		(end 438.033414 -260.21665)
		(width 0.381)
		(layer "F.Cu")
		(net "GND")
	)
	(segment
		(start 381.305816 -282.68422)
		(end 381.305816 -283.219906)
		(width 0.254)
		(layer "F.Cu")
		(net "GND")
	)
	(segment
		(start 378.486162 -282.683966)
		(end 378.486162 -283.219906)
		(width 0.254)
		(layer "F.Cu")
		(net "GND")
	)
	(segment
		(start 185.544714 -264.466578)
		(end 186.649614 -264.466578)
		(width 0.381)
		(layer "F.Cu")
		(net "GND")
	)
	(segment
		(start 352.641916 -268.84757)
		(end 352.641662 -268.847824)
		(width 0.254)
		(layer "F.Cu")
		(net "GND")
	)
	(segment
		(start 275.268182 -271.266666)
		(end 274.163282 -271.266666)
		(width 0.381)
		(layer "F.Cu")
		(net "GND")
	)
	(segment
		(start 254.975614 -263.616694)
		(end 256.080514 -263.616694)
		(width 0.381)
		(layer "F.Cu")
		(net "GND")
	)
	(segment
		(start 99.422712 -234.69219)
		(end 99.422712 -234.156504)
		(width 0.254)
		(layer "F.Cu")
		(net "GND")
	)
	(segment
		(start 310.207914 -313.766708)
		(end 308.887114 -313.766708)
		(width 0.381)
		(layer "F.Cu")
		(net "GND")
	)
	(segment
		(start 98.482912 -226.017582)
		(end 98.483166 -226.017328)
		(width 0.254)
		(layer "F.Cu")
		(net "GND")
	)
	(segment
		(start 22.123146 -204.96657)
		(end 23.228046 -204.96657)
		(width 0.381)
		(layer "F.Cu")
		(net "GND")
	)
	(segment
		(start 301.343314 -251.716794)
		(end 302.448214 -251.716794)
		(width 0.381)
		(layer "F.Cu")
		(net "GND")
	)
	(segment
		(start 170.457114 -310.366664)
		(end 171.817792 -310.366664)
		(width 0.381)
		(layer "F.Cu")
		(net "GND")
	)
	(segment
		(start 370.85778 -244.458744)
		(end 370.85778 -243.922804)
		(width 0.2032)
		(layer "F.Cu")
		(net "GND")
	)
	(segment
		(start 382.245362 -282.683966)
		(end 382.245616 -282.68422)
		(width 0.254)
		(layer "F.Cu")
		(net "GND")
	)
	(segment
		(start 297.899582 -207.51673)
		(end 299.004482 -207.51673)
		(width 0.381)
		(layer "F.Cu")
		(net "GND")
	)
	(segment
		(start 15.055088 -335.871312)
		(end 14.014958 -335.871312)
		(width 0.381)
		(layer "F.Cu")
		(net "GND")
	)
	(segment
		(start 410.853382 -230.466646)
		(end 411.958282 -230.466646)
		(width 0.381)
		(layer "F.Cu")
		(net "GND")
	)
	(segment
		(start 123.857512 -216.250774)
		(end 123.857766 -216.25052)
		(width 0.254)
		(layer "F.Cu")
		(net "GND")
	)
	(segment
		(start 88.255094 -272.917158)
		(end 88.255094 -273.453098)
		(width 0.2032)
		(layer "F.Cu")
		(net "GND")
	)
	(segment
		(start 49.959514 -266.1666)
		(end 51.064414 -266.1666)
		(width 0.381)
		(layer "F.Cu")
		(net "GND")
	)
	(segment
		(start 449.677282 -207.51673)
		(end 448.572382 -207.51673)
		(width 0.381)
		(layer "F.Cu")
		(net "GND")
	)
	(segment
		(start 210.514946 -270.416782)
		(end 211.619846 -270.416782)
		(width 0.381)
		(layer "F.Cu")
		(net "GND")
	)
	(segment
		(start 263.624314 -210.916774)
		(end 264.729214 -210.916774)
		(width 0.381)
		(layer "F.Cu")
		(net "GND")
	)
	(segment
		(start 189.26175 -13.599668)
		(end 189.26175 -13.1572)
		(width 0.3556)
		(layer "F.Cu")
		(net "GND")
	)
	(segment
		(start 443.367414 -220.266768)
		(end 444.472314 -220.266768)
		(width 0.381)
		(layer "F.Cu")
		(net "GND")
	)
	(segment
		(start 117.278912 -216.78646)
		(end 117.278912 -216.250774)
		(width 0.254)
		(layer "F.Cu")
		(net "GND")
	)
	(segment
		(start 133.255512 -219.506292)
		(end 133.255766 -219.506038)
		(width 0.254)
		(layer "F.Cu")
		(net "GND")
	)
	(segment
		(start 463.659982 -306.96662)
		(end 462.555082 -306.96662)
		(width 0.381)
		(layer "F.Cu")
		(net "GND")
	)
	(segment
		(start 15.684246 -307.816758)
		(end 16.789146 -307.816758)
		(width 0.381)
		(layer "F.Cu")
		(net "GND")
	)
	(segment
		(start 406.753314 -225.36658)
		(end 405.648414 -225.36658)
		(width 0.381)
		(layer "F.Cu")
		(net "GND")
	)
	(segment
		(start 267.724382 -301.01667)
		(end 268.829282 -301.01667)
		(width 0.381)
		(layer "F.Cu")
		(net "GND")
	)
	(segment
		(start 338.120736 -55.028846)
		(end 337.581748 -55.028846)
		(width 0.2032)
		(layer "F.Cu")
		(net "GND")
	)
	(segment
		(start 405.648414 -273.816572)
		(end 406.753314 -273.816572)
		(width 0.381)
		(layer "F.Cu")
		(net "GND")
	)
	(segment
		(start 96.138238 -414.35528)
		(end 95.26778 -414.35528)
		(width 0.3556)
		(layer "F.Cu")
		(net "GND")
	)
	(segment
		(start 210.64728 -75.377548)
		(end 210.92414 -75.654408)
		(width 0.3556)
		(layer "F.Cu")
		(net "GND")
	)
	(segment
		(start 49.959514 -314.616592)
		(end 48.854614 -314.616592)
		(width 0.381)
		(layer "F.Cu")
		(net "GND")
	)
	(segment
		(start 301.343314 -197.316598)
		(end 302.448214 -197.316598)
		(width 0.381)
		(layer "F.Cu")
		(net "GND")
	)
	(segment
		(start 129.136648 -261.244588)
		(end 129.136394 -261.244842)
		(width 0.2032)
		(layer "F.Cu")
		(net "GND")
	)
	(segment
		(start 328.913998 -190.34506)
		(end 328.913998 -189.72911)
		(width 0.3556)
		(layer "F.Cu")
		(net "GND")
	)
	(segment
		(start 215.719914 -224.516696)
		(end 216.824814 -224.516696)
		(width 0.381)
		(layer "F.Cu")
		(net "GND")
	)
	(segment
		(start 129.606294 -271.289272)
		(end 129.606548 -271.825212)
		(width 0.2032)
		(layer "F.Cu")
		(net "GND")
	)
	(segment
		(start 276.373082 -301.01667)
		(end 275.268182 -301.01667)
		(width 0.381)
		(layer "F.Cu")
		(net "GND")
	)
	(segment
		(start 53.403246 -225.36658)
		(end 54.508146 -225.36658)
		(width 0.381)
		(layer "F.Cu")
		(net "GND")
	)
	(segment
		(start 111.640112 -226.553268)
		(end 111.640112 -226.017582)
		(width 0.254)
		(layer "F.Cu")
		(net "GND")
	)
	(segment
		(start 99.422712 -216.250774)
		(end 99.422966 -216.25052)
		(width 0.254)
		(layer "F.Cu")
		(net "GND")
	)
	(segment
		(start 214.615014 -228.766624)
		(end 215.719914 -228.766624)
		(width 0.381)
		(layer "F.Cu")
		(net "GND")
	)
	(segment
		(start 329.980036 -42.811446)
		(end 329.441048 -42.811446)
		(width 0.2032)
		(layer "F.Cu")
		(net "GND")
	)
	(segment
		(start 349.822516 -273.730974)
		(end 349.822516 -274.26666)
		(width 0.254)
		(layer "F.Cu")
		(net "GND")
	)
	(segment
		(start 347.36278 -237.947454)
		(end 347.363034 -237.947454)
		(width 0.254)
		(layer "F.Cu")
		(net "GND")
	)
	(segment
		(start 300.238414 -290.816792)
		(end 301.343314 -290.816792)
		(width 0.381)
		(layer "F.Cu")
		(net "GND")
	)
	(segment
		(start 427.729904 -120.365012)
		(end 428.22368 -120.365012)
		(width 0.381)
		(layer "F.Cu")
		(net "GND")
	)
	(segment
		(start 307.858414 -221.96679)
		(end 308.887114 -221.96679)
		(width 0.381)
		(layer "F.Cu")
		(net "GND")
	)
	(segment
		(start 182.58282 -419.07333)
		(end 181.89956 -419.07333)
		(width 0.3556)
		(layer "F.Cu")
		(net "GND")
	)
	(segment
		(start 432.379882 -215.166702)
		(end 433.484782 -215.166702)
		(width 0.381)
		(layer "F.Cu")
		(net "GND")
	)
	(segment
		(start 34.871914 -310.366664)
		(end 35.976814 -310.366664)
		(width 0.381)
		(layer "F.Cu")
		(net "GND")
	)
	(segment
		(start 178.425348 -425.007532)
		(end 178.78552 -424.64736)
		(width 0.3556)
		(layer "F.Cu")
		(net "GND")
	)
	(segment
		(start 87.785194 -268.84757)
		(end 87.785194 -269.38351)
		(width 0.254)
		(layer "F.Cu")
		(net "GND")
	)
	(segment
		(start 27.328114 -316.316614)
		(end 28.433014 -316.316614)
		(width 0.381)
		(layer "F.Cu")
		(net "GND")
	)
	(segment
		(start 178.000914 -278.916638)
		(end 179.105814 -278.916638)
		(width 0.381)
		(layer "F.Cu")
		(net "GND")
	)
	(segment
		(start 126.786894 -255.011682)
		(end 126.786894 -255.547622)
		(width 0.2032)
		(layer "F.Cu")
		(net "GND")
	)
	(segment
		(start 178.000914 -314.616592)
		(end 179.105814 -314.616592)
		(width 0.381)
		(layer "F.Cu")
		(net "GND")
	)
	(segment
		(start 458.455014 -315.46673)
		(end 459.559914 -315.46673)
		(width 0.381)
		(layer "F.Cu")
		(net "GND")
	)
	(segment
		(start 136.545066 -234.97032)
		(end 136.544812 -234.970066)
		(width 0.2032)
		(layer "F.Cu")
		(net "GND")
	)
	(segment
		(start 420.736014 -234.716574)
		(end 421.840914 -234.716574)
		(width 0.381)
		(layer "F.Cu")
		(net "GND")
	)
	(segment
		(start 27.547062 -11.26998)
		(end 27.547062 -12.37488)
		(width 0.3556)
		(layer "F.Cu")
		(net "GND")
	)
	(segment
		(start 444.472314 -267.016738)
		(end 443.367414 -267.016738)
		(width 0.381)
		(layer "F.Cu")
		(net "GND")
	)
	(segment
		(start 275.268182 -308.666642)
		(end 274.163282 -308.666642)
		(width 0.381)
		(layer "F.Cu")
		(net "GND")
	)
	(segment
		(start 23.7236 -76.266548)
		(end 23.0378 -76.266548)
		(width 0.3556)
		(layer "F.Cu")
		(net "GND")
	)
	(segment
		(start 19.784314 -288.266632)
		(end 20.889214 -288.266632)
		(width 0.381)
		(layer "F.Cu")
		(net "GND")
	)
	(segment
		(start 99.422712 -223.297496)
		(end 99.422712 -222.76181)
		(width 0.254)
		(layer "F.Cu")
		(net "GND")
	)
	(segment
		(start 195.427346 -231.316784)
		(end 196.532246 -231.316784)
		(width 0.381)
		(layer "F.Cu")
		(net "GND")
	)
	(segment
		(start 110.340648 -276.986492)
		(end 110.340648 -277.522178)
		(width 0.254)
		(layer "F.Cu")
		(net "GND")
	)
	(segment
		(start 458.455014 -295.06672)
		(end 459.559914 -295.06672)
		(width 0.381)
		(layer "F.Cu")
		(net "GND")
	)
	(segment
		(start 137.484866 -243.644928)
		(end 136.545066 -243.108988)
		(width 0.254)
		(layer "F.Cu")
		(net "GND")
	)
	(segment
		(start 208.09331 -121.1072)
		(end 207.391 -121.1072)
		(width 0.3556)
		(layer "F.Cu")
		(net "GND")
	)
	(segment
		(start 328.168 -52.303934)
		(end 328.168 -52.028852)
		(width 0.2032)
		(layer "F.Cu")
		(net "GND")
	)
	(segment
		(start 195.427346 -221.96679)
		(end 196.532246 -221.96679)
		(width 0.381)
		(layer "F.Cu")
		(net "GND")
	)
	(segment
		(start 124.327666 -228.99497)
		(end 124.327412 -228.994716)
		(width 0.254)
		(layer "F.Cu")
		(net "GND")
	)
	(segment
		(start 8.140446 -221.96679)
		(end 9.245346 -221.96679)
		(width 0.381)
		(layer "F.Cu")
		(net "GND")
	)
	(segment
		(start 185.544714 -314.616592)
		(end 184.439814 -314.616592)
		(width 0.381)
		(layer "F.Cu")
		(net "GND")
	)
	(segment
		(start 22.123146 -281.466798)
		(end 23.228046 -281.466798)
		(width 0.381)
		(layer "F.Cu")
		(net "GND")
	)
	(segment
		(start 349.712534 -245.27256)
		(end 349.71228 -245.272306)
		(width 0.2032)
		(layer "F.Cu")
		(net "GND")
	)
	(segment
		(start 294.904414 -300.166786)
		(end 293.799514 -300.166786)
		(width 0.381)
		(layer "F.Cu")
		(net "GND")
	)
	(segment
		(start 53.403246 -289.11677)
		(end 54.508146 -289.11677)
		(width 0.381)
		(layer "F.Cu")
		(net "GND")
	)
	(segment
		(start 345.554554 -50.951384)
		(end 345.15171 -51.59248)
		(width 0.1778)
		(layer "F.Cu")
		(net "GND")
	)
	(segment
		(start 45.859446 -250.016772)
		(end 46.964346 -250.016772)
		(width 0.381)
		(layer "F.Cu")
		(net "GND")
	)
	(segment
		(start 191.983614 -308.666642)
		(end 193.088514 -308.666642)
		(width 0.381)
		(layer "F.Cu")
		(net "GND")
	)
	(segment
		(start 383.075434 -228.180646)
		(end 383.075434 -227.64496)
		(width 0.2032)
		(layer "F.Cu")
		(net "GND")
	)
	(segment
		(start 429.384714 -263.616694)
		(end 430.489614 -263.616694)
		(width 0.381)
		(layer "F.Cu")
		(net "GND")
	)
	(segment
		(start 436.928514 -292.516814)
		(end 438.033414 -292.516814)
		(width 0.381)
		(layer "F.Cu")
		(net "GND")
	)
	(segment
		(start 116.922042 -129.967482)
		(end 117.351048 -130.396488)
		(width 0.3556)
		(layer "F.Cu")
		(net "GND")
	)
	(segment
		(start 23.228046 -244.916706)
		(end 24.332946 -244.916706)
		(width 0.381)
		(layer "F.Cu")
		(net "GND")
	)
	(segment
		(start 290.355782 -226.216718)
		(end 289.250882 -226.216718)
		(width 0.381)
		(layer "F.Cu")
		(net "GND")
	)
	(segment
		(start 113.519712 -248.80697)
		(end 113.52022 -248.806462)
		(width 0.254)
		(layer "F.Cu")
		(net "GND")
	)
	(segment
		(start 286.255714 -242.3668)
		(end 287.360614 -242.3668)
		(width 0.381)
		(layer "F.Cu")
		(net "GND")
	)
	(segment
		(start 334.097376 -49.649888)
		(end 333.23657 -49.390046)
		(width 0.2032)
		(layer "F.Cu")
		(net "GND")
	)
	(segment
		(start 377.546362 -262.058404)
		(end 377.546616 -262.058658)
		(width 0.254)
		(layer "F.Cu")
		(net "GND")
	)
	(segment
		(start 15.684246 -313.766708)
		(end 16.789146 -313.766708)
		(width 0.381)
		(layer "F.Cu")
		(net "GND")
	)
	(segment
		(start 111.640112 -223.297496)
		(end 111.640112 -222.76181)
		(width 0.254)
		(layer "F.Cu")
		(net "GND")
	)
	(segment
		(start 374.726962 -282.683966)
		(end 374.726962 -283.219906)
		(width 0.254)
		(layer "F.Cu")
		(net "GND")
	)
	(segment
		(start 357.810562 -276.172676)
		(end 357.810562 -276.708616)
		(width 0.254)
		(layer "F.Cu")
		(net "GND")
	)
	(segment
		(start 63.726314 -271.266666)
		(end 65.047114 -271.266666)
		(width 0.381)
		(layer "F.Cu")
		(net "GND")
	)
	(segment
		(start 449.677282 -301.01667)
		(end 448.572382 -301.01667)
		(width 0.381)
		(layer "F.Cu")
		(net "GND")
	)
	(segment
		(start 178.000914 -216.866724)
		(end 176.896014 -216.866724)
		(width 0.381)
		(layer "F.Cu")
		(net "GND")
	)
	(segment
		(start 84.856066 -237.133892)
		(end 84.385912 -237.411768)
		(width 0.2032)
		(layer "F.Cu")
		(net "GND")
	)
	(segment
		(start 215.719914 -205.816708)
		(end 216.824814 -205.816708)
		(width 0.381)
		(layer "F.Cu")
		(net "GND")
	)
	(segment
		(start 15.684246 -248.31675)
		(end 16.789146 -248.31675)
		(width 0.381)
		(layer "F.Cu")
		(net "GND")
	)
	(segment
		(start 180.339746 -233.016806)
		(end 181.444646 -233.016806)
		(width 0.381)
		(layer "F.Cu")
		(net "GND")
	)
	(segment
		(start 94.723966 -241.202972)
		(end 94.723966 -240.667286)
		(width 0.2032)
		(layer "F.Cu")
		(net "GND")
	)
	(segment
		(start 185.544714 -228.766624)
		(end 186.649614 -228.766624)
		(width 0.381)
		(layer "F.Cu")
		(net "GND")
	)
	(segment
		(start 456.116182 -267.866622)
		(end 455.011282 -267.866622)
		(width 0.381)
		(layer "F.Cu")
		(net "GND")
	)
	(segment
		(start 373.787162 -268.033754)
		(end 373.787416 -268.569694)
		(width 0.2032)
		(layer "F.Cu")
		(net "GND")
	)
	(segment
		(start 94.597728 -334.191102)
		(end 94.292674 -334.191102)
		(width 0.2032)
		(layer "F.Cu")
		(net "GND")
	)
	(segment
		(start 457.221082 -306.96662)
		(end 456.116182 -306.96662)
		(width 0.381)
		(layer "F.Cu")
		(net "GND")
	)
	(segment
		(start 230.984044 -56.964834)
		(end 230.984298 -56.965088)
		(width 0.381)
		(layer "F.Cu")
		(net "GND")
	)
	(segment
		(start 149.498558 -73.285858)
		(end 149.498558 -72.608948)
		(width 0.3556)
		(layer "F.Cu")
		(net "GND")
	)
	(segment
		(start 170.457114 -216.866724)
		(end 171.809918 -216.866724)
		(width 0.381)
		(layer "F.Cu")
		(net "GND")
	)
	(segment
		(start 304.338482 -245.76659)
		(end 305.443382 -245.76659)
		(width 0.381)
		(layer "F.Cu")
		(net "GND")
	)
	(segment
		(start 56.398414 -308.666642)
		(end 57.503314 -308.666642)
		(width 0.381)
		(layer "F.Cu")
		(net "GND")
	)
	(segment
		(start 115.521994 -358.93375)
		(end 115.106704 -358.93375)
		(width 0.3556)
		(layer "F.Cu")
		(net "GND")
	)
	(segment
		(start 136.545066 -219.228162)
		(end 136.545066 -218.692222)
		(width 0.2032)
		(layer "F.Cu")
		(net "GND")
	)
	(segment
		(start 429.384714 -212.616796)
		(end 430.489614 -212.616796)
		(width 0.381)
		(layer "F.Cu")
		(net "GND")
	)
	(segment
		(start 344.07348 -235.505752)
		(end 344.07348 -234.970066)
		(width 0.2032)
		(layer "F.Cu")
		(net "GND")
	)
	(segment
		(start 121.977912 -216.250774)
		(end 121.978166 -216.25052)
		(width 0.254)
		(layer "F.Cu")
		(net "GND")
	)
	(segment
		(start 343.60358 -247.178576)
		(end 343.603834 -247.178322)
		(width 0.2032)
		(layer "F.Cu")
		(net "GND")
	)
	(segment
		(start 207.071214 -216.866724)
		(end 208.176114 -216.866724)
		(width 0.381)
		(layer "F.Cu")
		(net "GND")
	)
	(segment
		(start 433.484782 -286.56661)
		(end 434.589682 -286.56661)
		(width 0.381)
		(layer "F.Cu")
		(net "GND")
	)
	(segment
		(start 340.424516 -257.45313)
		(end 340.424516 -257.98907)
		(width 0.2032)
		(layer "F.Cu")
		(net "GND")
	)
	(segment
		(start 19.784314 -230.466646)
		(end 20.889214 -230.466646)
		(width 0.381)
		(layer "F.Cu")
		(net "GND")
	)
	(segment
		(start 266.619482 -266.1666)
		(end 267.724382 -266.1666)
		(width 0.381)
		(layer "F.Cu")
		(net "GND")
	)
	(segment
		(start 93.140784 -93.817948)
		(end 93.145356 -93.813376)
		(width 0.3556)
		(layer "F.Cu")
		(net "GND")
	)
	(segment
		(start 53.403246 -276.366732)
		(end 54.724046 -276.366732)
		(width 0.381)
		(layer "F.Cu")
		(net "GND")
	)
	(segment
		(start 49.959514 -284.866588)
		(end 51.064414 -284.866588)
		(width 0.381)
		(layer "F.Cu")
		(net "GND")
	)
	(segment
		(start 266.619482 -228.766624)
		(end 267.724382 -228.766624)
		(width 0.381)
		(layer "F.Cu")
		(net "GND")
	)
	(segment
		(start 281.707082 -294.216582)
		(end 282.811982 -294.216582)
		(width 0.381)
		(layer "F.Cu")
		(net "GND")
	)
	(segment
		(start 15.684246 -195.616576)
		(end 16.789146 -195.616576)
		(width 0.381)
		(layer "F.Cu")
		(net "GND")
	)
	(segment
		(start 367.098834 -220.041724)
		(end 367.098834 -219.506038)
		(width 0.254)
		(layer "F.Cu")
		(net "GND")
	)
	(segment
		(start 311.882282 -205.816708)
		(end 312.987182 -205.816708)
		(width 0.381)
		(layer "F.Cu")
		(net "GND")
	)
	(segment
		(start 344.903552 -39.295324)
		(end 345.318588 -38.880288)
		(width 0.2032)
		(layer "F.Cu")
		(net "GND")
	)
	(segment
		(start 408.061414 -236.397038)
		(end 407.677874 -236.397038)
		(width 0.381)
		(layer "F.Cu")
		(net "GND")
	)
	(segment
		(start 30.771846 -242.3668)
		(end 31.876746 -242.3668)
		(width 0.381)
		(layer "F.Cu")
		(net "GND")
	)
	(segment
		(start 14.579346 -248.31675)
		(end 15.684246 -248.31675)
		(width 0.381)
		(layer "F.Cu")
		(net "GND")
	)
	(segment
		(start 337.699858 -47.650146)
		(end 337.299808 -47.250096)
		(width 0.2032)
		(layer "F.Cu")
		(net "GND")
	)
	(segment
		(start 57.503314 -250.866656)
		(end 56.398414 -250.866656)
		(width 0.381)
		(layer "F.Cu")
		(net "GND")
	)
	(segment
		(start 103.291894 -272.917158)
		(end 103.291894 -273.453098)
		(width 0.2032)
		(layer "F.Cu")
		(net "GND")
	)
	(segment
		(start 419.75786 -310.366664)
		(end 418.397182 -310.366664)
		(width 0.381)
		(layer "F.Cu")
		(net "GND")
	)
	(segment
		(start 188.988446 -289.11677)
		(end 190.093346 -289.11677)
		(width 0.381)
		(layer "F.Cu")
		(net "GND")
	)
	(segment
		(start 379.425962 -281.591512)
		(end 379.426216 -281.591766)
		(width 0.254)
		(layer "F.Cu")
		(net "GND")
	)
	(segment
		(start 129.026666 -217.600276)
		(end 129.026666 -217.064336)
		(width 0.254)
		(layer "F.Cu")
		(net "GND")
	)
	(segment
		(start 459.559914 -199.01662)
		(end 458.455014 -199.01662)
		(width 0.381)
		(layer "F.Cu")
		(net "GND")
	)
	(segment
		(start 301.133764 -14.506194)
		(end 301.133764 -15.552674)
		(width 0.3556)
		(layer "F.Cu")
		(net "GND")
	)
	(segment
		(start 52.298346 -221.96679)
		(end 53.403246 -221.96679)
		(width 0.381)
		(layer "F.Cu")
		(net "GND")
	)
	(segment
		(start 347.003116 -287.288986)
		(end 347.002862 -287.28924)
		(width 0.254)
		(layer "F.Cu")
		(net "GND")
	)
	(segment
		(start 347.876622 -37.758878)
		(end 347.345 -38.2905)
		(width 0.2032)
		(layer "F.Cu")
		(net "GND")
	)
	(segment
		(start 123.857512 -226.017582)
		(end 123.857766 -226.017328)
		(width 0.254)
		(layer "F.Cu")
		(net "GND")
	)
	(segment
		(start 26.223214 -297.616626)
		(end 27.328114 -297.616626)
		(width 0.381)
		(layer "F.Cu")
		(net "GND")
	)
	(segment
		(start 125.737112 -223.297496)
		(end 125.737112 -222.76181)
		(width 0.254)
		(layer "F.Cu")
		(net "GND")
	)
	(segment
		(start 21.690838 -114.431826)
		(end 22.409404 -114.431826)
		(width 0.3556)
		(layer "F.Cu")
		(net "GND")
	)
	(segment
		(start 336.555334 -245.27256)
		(end 336.55508 -245.272306)
		(width 0.2032)
		(layer "F.Cu")
		(net "GND")
	)
	(segment
		(start 95.303594 -267.220192)
		(end 95.303594 -267.755878)
		(width 0.2032)
		(layer "F.Cu")
		(net "GND")
	)
	(segment
		(start 12.240514 -269.566644)
		(end 13.345414 -269.566644)
		(width 0.381)
		(layer "F.Cu")
		(net "GND")
	)
	(segment
		(start 427.766988 -8.320024)
		(end 427.766988 -7.215124)
		(width 0.3556)
		(layer "F.Cu")
		(net "GND")
	)
	(segment
		(start 296.794682 -216.866724)
		(end 297.899582 -216.866724)
		(width 0.381)
		(layer "F.Cu")
		(net "GND")
	)
	(segment
		(start 30.771846 -309.51678)
		(end 31.876746 -309.51678)
		(width 0.381)
		(layer "F.Cu")
		(net "GND")
	)
	(segment
		(start 345.953334 -232.250488)
		(end 345.95308 -232.250234)
		(width 0.2032)
		(layer "F.Cu")
		(net "GND")
	)
	(segment
		(start 366.738916 -280.77795)
		(end 366.738662 -280.778204)
		(width 0.254)
		(layer "F.Cu")
		(net "GND")
	)
	(segment
		(start 142.48384 -107.795568)
		(end 142.0622 -107.373928)
		(width 0.3556)
		(layer "F.Cu")
		(net "GND")
	)
	(segment
		(start 171.50588 -130.666998)
		(end 171.50588 -131.280408)
		(width 0.3556)
		(layer "F.Cu")
		(net "GND")
	)
	(segment
		(start 297.899582 -258.516628)
		(end 299.004482 -258.516628)
		(width 0.381)
		(layer "F.Cu")
		(net "GND")
	)
	(segment
		(start 212.44306 -69.157088)
		(end 212.39734 -69.202808)
		(width 0.3556)
		(layer "F.Cu")
		(net "GND")
	)
	(segment
		(start 199.527414 -282.316682)
		(end 200.632314 -282.316682)
		(width 0.381)
		(layer "F.Cu")
		(net "GND")
	)
	(segment
		(start 366.268762 -264.778236)
		(end 366.268762 -265.314176)
		(width 0.254)
		(layer "F.Cu")
		(net "GND")
	)
	(segment
		(start 134.775448 -285.125414)
		(end 134.775448 -285.6611)
		(width 0.2032)
		(layer "F.Cu")
		(net "GND")
	)
	(segment
		(start 263.624314 -203.266802)
		(end 264.729214 -203.266802)
		(width 0.381)
		(layer "F.Cu")
		(net "GND")
	)
	(segment
		(start 91.544648 -259.081016)
		(end 91.544648 -259.616956)
		(width 0.2032)
		(layer "F.Cu")
		(net "GND")
	)
	(segment
		(start 127.239776 -337.601306)
		(end 126.946152 -337.601306)
		(width 0.2032)
		(layer "F.Cu")
		(net "GND")
	)
	(segment
		(start 153.359866 -124.363988)
		(end 153.359866 -123.678188)
		(width 0.3556)
		(layer "F.Cu")
		(net "GND")
	)
	(segment
		(start 260.180582 -266.1666)
		(end 259.075682 -266.1666)
		(width 0.381)
		(layer "F.Cu")
		(net "GND")
	)
	(segment
		(start 212.724746 -283.166566)
		(end 211.619846 -283.166566)
		(width 0.381)
		(layer "F.Cu")
		(net "GND")
	)
	(segment
		(start 98.013012 -246.900192)
		(end 98.013012 -246.364506)
		(width 0.2032)
		(layer "F.Cu")
		(net "GND")
	)
	(segment
		(start 193.088514 -204.116686)
		(end 191.983614 -204.116686)
		(width 0.381)
		(layer "F.Cu")
		(net "GND")
	)
	(segment
		(start 123.857512 -216.78646)
		(end 123.857512 -216.250774)
		(width 0.254)
		(layer "F.Cu")
		(net "GND")
	)
	(segment
		(start 406.753314 -273.816572)
		(end 407.858214 -273.816572)
		(width 0.381)
		(layer "F.Cu")
		(net "GND")
	)
	(segment
		(start 170.457114 -224.516696)
		(end 169.352214 -224.516696)
		(width 0.381)
		(layer "F.Cu")
		(net "GND")
	)
	(segment
		(start 278.711914 -298.466764)
		(end 279.816814 -298.466764)
		(width 0.381)
		(layer "F.Cu")
		(net "GND")
	)
	(segment
		(start 453.121014 -242.3668)
		(end 452.016114 -242.3668)
		(width 0.381)
		(layer "F.Cu")
		(net "GND")
	)
	(segment
		(start 232.000044 -58.764932)
		(end 230.984044 -58.764932)
		(width 0.381)
		(layer "F.Cu")
		(net "GND")
	)
	(segment
		(start 303.281842 -435.585108)
		(end 303.834546 -436.137812)
		(width 0.3556)
		(layer "F.Cu")
		(net "GND")
	)
	(segment
		(start 65.047114 -202.416664)
		(end 66.152014 -202.416664)
		(width 0.381)
		(layer "F.Cu")
		(net "GND")
	)
	(segment
		(start 97.183448 -257.45313)
		(end 97.183448 -257.98907)
		(width 0.2032)
		(layer "F.Cu")
		(net "GND")
	)
	(segment
		(start 409.558998 -312.892948)
		(end 409.58262 -312.91657)
		(width 0.381)
		(layer "F.Cu")
		(net "GND")
	)
	(segment
		(start 281.707082 -314.616592)
		(end 282.811982 -314.616592)
		(width 0.381)
		(layer "F.Cu")
		(net "GND")
	)
	(segment
		(start 433.484782 -241.516662)
		(end 434.589682 -241.516662)
		(width 0.381)
		(layer "F.Cu")
		(net "GND")
	)
	(segment
		(start 165.252146 -206.666592)
		(end 166.357046 -206.666592)
		(width 0.381)
		(layer "F.Cu")
		(net "GND")
	)
	(segment
		(start 158.813246 -234.716574)
		(end 157.708346 -234.716574)
		(width 0.381)
		(layer "F.Cu")
		(net "GND")
	)
	(segment
		(start 376.49658 -237.947454)
		(end 376.496834 -237.947454)
		(width 0.254)
		(layer "F.Cu")
		(net "GND")
	)
	(segment
		(start 179.105814 -232.166668)
		(end 178.000914 -232.166668)
		(width 0.381)
		(layer "F.Cu")
		(net "GND")
	)
	(segment
		(start 429.384714 -276.366732)
		(end 430.489614 -276.366732)
		(width 0.381)
		(layer "F.Cu")
		(net "GND")
	)
	(segment
		(start 413.192214 -301.866808)
		(end 414.297114 -301.866808)
		(width 0.381)
		(layer "F.Cu")
		(net "GND")
	)
	(segment
		(start 34.871914 -280.61666)
		(end 33.767014 -280.61666)
		(width 0.381)
		(layer "F.Cu")
		(net "GND")
	)
	(segment
		(start 184.439814 -211.766658)
		(end 185.544714 -211.766658)
		(width 0.381)
		(layer "F.Cu")
		(net "GND")
	)
	(segment
		(start 207.071214 -207.51673)
		(end 208.176114 -207.51673)
		(width 0.381)
		(layer "F.Cu")
		(net "GND")
	)
	(segment
		(start 373.677434 -244.45849)
		(end 373.677434 -243.922804)
		(width 0.2032)
		(layer "F.Cu")
		(net "GND")
	)
	(segment
		(start 358.280716 -285.6611)
		(end 358.280462 -285.661354)
		(width 0.254)
		(layer "F.Cu")
		(net "GND")
	)
	(segment
		(start 361.569762 -259.894832)
		(end 361.569762 -260.430772)
		(width 0.254)
		(layer "F.Cu")
		(net "GND")
	)
	(segment
		(start 37.330634 -106.523282)
		(end 37.940234 -106.523282)
		(width 0.3556)
		(layer "F.Cu")
		(net "GND")
	)
	(segment
		(start 161.61893 -312.892948)
		(end 161.54273 -312.892948)
		(width 0.381)
		(layer "F.Cu")
		(net "GND")
	)
	(segment
		(start 56.398414 -247.466612)
		(end 57.503314 -247.466612)
		(width 0.381)
		(layer "F.Cu")
		(net "GND")
	)
	(segment
		(start 333.439008 -44.343828)
		(end 333.510382 -44.221146)
		(width 0.2032)
		(layer "F.Cu")
		(net "GND")
	)
	(segment
		(start 308.887114 -242.3668)
		(end 309.992014 -242.3668)
		(width 0.381)
		(layer "F.Cu")
		(net "GND")
	)
	(segment
		(start 439.923682 -291.666676)
		(end 441.028582 -291.666676)
		(width 0.381)
		(layer "F.Cu")
		(net "GND")
	)
	(segment
		(start 346.319348 -38.880288)
		(end 346.384626 -38.945566)
		(width 0.2032)
		(layer "F.Cu")
		(net "GND")
	)
	(segment
		(start 321.8561 -76.985114)
		(end 321.8561 -77.723492)
		(width 0.3556)
		(layer "F.Cu")
		(net "GND")
	)
	(segment
		(start 378.84608 -245.272306)
		(end 378.84608 -244.73662)
		(width 0.2032)
		(layer "F.Cu")
		(net "GND")
	)
	(segment
		(start 293.799514 -208.366614)
		(end 292.694614 -208.366614)
		(width 0.381)
		(layer "F.Cu")
		(net "GND")
	)
	(segment
		(start 150.53056 -39.693088)
		(end 150.54834 -39.710868)
		(width 0.3556)
		(layer "F.Cu")
		(net "GND")
	)
	(segment
		(start 210.92414 -75.654408)
		(end 214.75827 -75.654408)
		(width 0.3556)
		(layer "F.Cu")
		(net "GND")
	)
	(segment
		(start 133.725412 -365.747808)
		(end 134.42315 -365.05007)
		(width 0.508)
		(layer "F.Cu")
		(net "GND")
	)
	(segment
		(start 382.605534 -224.111566)
		(end 382.605534 -223.575626)
		(width 0.2032)
		(layer "F.Cu")
		(net "GND")
	)
	(segment
		(start 15.684246 -246.616728)
		(end 16.789146 -246.616728)
		(width 0.381)
		(layer "F.Cu")
		(net "GND")
	)
	(segment
		(start 102.822248 -283.497782)
		(end 102.822248 -284.033468)
		(width 0.254)
		(layer "F.Cu")
		(net "GND")
	)
	(segment
		(start 422.909238 -154.251914)
		(end 422.909238 -153.609548)
		(width 0.3556)
		(layer "F.Cu")
		(net "GND")
	)
	(segment
		(start 57.503314 -244.066568)
		(end 58.608214 -244.066568)
		(width 0.381)
		(layer "F.Cu")
		(net "GND")
	)
	(segment
		(start 101.302312 -249.342148)
		(end 101.302312 -248.806208)
		(width 0.2032)
		(layer "F.Cu")
		(net "GND")
	)
	(segment
		(start 305.443382 -211.766658)
		(end 306.548282 -211.766658)
		(width 0.381)
		(layer "F.Cu")
		(net "GND")
	)
	(segment
		(start 91.434666 -220.855794)
		(end 91.434666 -220.319854)
		(width 0.2032)
		(layer "F.Cu")
		(net "GND")
	)
	(segment
		(start 445.577214 -199.01662)
		(end 444.472314 -199.01662)
		(width 0.381)
		(layer "F.Cu")
		(net "GND")
	)
	(segment
		(start 349.352362 -279.428194)
		(end 349.352362 -279.96388)
		(width 0.2032)
		(layer "F.Cu")
		(net "GND")
	)
	(segment
		(start 351.12198 -216.78646)
		(end 351.12198 -216.250774)
		(width 0.254)
		(layer "F.Cu")
		(net "GND")
	)
	(segment
		(start 375.666762 -263.150604)
		(end 375.666762 -263.68629)
		(width 0.2032)
		(layer "F.Cu")
		(net "GND")
	)
	(segment
		(start 361.652566 -365.769144)
		(end 361.652566 -366.465104)
		(width 0.381)
		(layer "F.Cu")
		(net "GND")
	)
	(segment
		(start 345.123516 -257.45313)
		(end 345.123516 -257.98907)
		(width 0.2032)
		(layer "F.Cu")
		(net "GND")
	)
	(segment
		(start 49.959514 -244.066568)
		(end 51.064414 -244.066568)
		(width 0.381)
		(layer "F.Cu")
		(net "GND")
	)
	(segment
		(start 266.619482 -299.316648)
		(end 267.724382 -299.316648)
		(width 0.381)
		(layer "F.Cu")
		(net "GND")
	)
	(segment
		(start 18.679414 -286.56661)
		(end 19.784314 -286.56661)
		(width 0.381)
		(layer "F.Cu")
		(net "GND")
	)
	(segment
		(start 410.853382 -272.966688)
		(end 412.161482 -272.966688)
		(width 0.381)
		(layer "F.Cu")
		(net "GND")
	)
	(segment
		(start 196.532246 -285.716726)
		(end 195.427346 -285.716726)
		(width 0.381)
		(layer "F.Cu")
		(net "GND")
	)
	(segment
		(start 361.569762 -287.567116)
		(end 361.569762 -288.103056)
		(width 0.254)
		(layer "F.Cu")
		(net "GND")
	)
	(segment
		(start 43.520614 -272.966688)
		(end 42.415714 -272.966688)
		(width 0.381)
		(layer "F.Cu")
		(net "GND")
	)
	(segment
		(start 176.896014 -308.666642)
		(end 178.000914 -308.666642)
		(width 0.381)
		(layer "F.Cu")
		(net "GND")
	)
	(segment
		(start 298.66082 -418.62756)
		(end 298.66082 -417.990528)
		(width 0.3556)
		(layer "F.Cu")
		(net "GND")
	)
	(segment
		(start 127.616712 -220.041978)
		(end 127.616966 -220.041724)
		(width 0.254)
		(layer "F.Cu")
		(net "GND")
	)
	(segment
		(start 406.753314 -283.166566)
		(end 405.445214 -283.166566)
		(width 0.381)
		(layer "F.Cu")
		(net "GND")
	)
	(segment
		(start 94.833694 -268.033754)
		(end 94.833694 -268.569694)
		(width 0.2032)
		(layer "F.Cu")
		(net "GND")
	)
	(segment
		(start 370.388134 -232.250488)
		(end 370.388134 -231.714548)
		(width 0.254)
		(layer "F.Cu")
		(net "GND")
	)
	(segment
		(start 379.896116 -281.869896)
		(end 379.896116 -282.405582)
		(width 0.254)
		(layer "F.Cu")
		(net "GND")
	)
	(segment
		(start 421.840914 -229.616762)
		(end 422.945814 -229.616762)
		(width 0.381)
		(layer "F.Cu")
		(net "GND")
	)
	(segment
		(start 158.813246 -272.116804)
		(end 160.121346 -272.116804)
		(width 0.381)
		(layer "F.Cu")
		(net "GND")
	)
	(segment
		(start 65.047114 -200.716642)
		(end 66.152014 -200.716642)
		(width 0.381)
		(layer "F.Cu")
		(net "GND")
	)
	(segment
		(start 214.615014 -282.316682)
		(end 215.719914 -282.316682)
		(width 0.381)
		(layer "F.Cu")
		(net "GND")
	)
	(segment
		(start 425.940982 -295.916604)
		(end 424.836082 -295.916604)
		(width 0.381)
		(layer "F.Cu")
		(net "GND")
	)
	(segment
		(start 32.361378 -99.586034)
		(end 31.751778 -99.586034)
		(width 0.3556)
		(layer "F.Cu")
		(net "GND")
	)
	(segment
		(start 328.625708 -47.510446)
		(end 328.244962 -46.949614)
		(width 0.1778)
		(layer "F.Cu")
		(net "GND")
	)
	(segment
		(start 175.005746 -201.56678)
		(end 173.900846 -201.56678)
		(width 0.381)
		(layer "F.Cu")
		(net "GND")
	)
	(segment
		(start 256.080514 -292.516814)
		(end 257.185414 -292.516814)
		(width 0.381)
		(layer "F.Cu")
		(net "GND")
	)
	(segment
		(start 195.427346 -238.966756)
		(end 196.532246 -238.966756)
		(width 0.381)
		(layer "F.Cu")
		(net "GND")
	)
	(segment
		(start 305.443382 -266.1666)
		(end 306.548282 -266.1666)
		(width 0.381)
		(layer "F.Cu")
		(net "GND")
	)
	(segment
		(start 37.330634 -105.425748)
		(end 37.330634 -106.523282)
		(width 0.3556)
		(layer "F.Cu")
		(net "GND")
	)
	(segment
		(start 44.754546 -206.666592)
		(end 45.859446 -206.666592)
		(width 0.381)
		(layer "F.Cu")
		(net "GND")
	)
	(segment
		(start 39.420546 -248.31675)
		(end 38.315646 -248.31675)
		(width 0.381)
		(layer "F.Cu")
		(net "GND")
	)
	(segment
		(start 448.572382 -303.566576)
		(end 447.467482 -303.566576)
		(width 0.381)
		(layer "F.Cu")
		(net "GND")
	)
	(segment
		(start 111.640112 -229.808786)
		(end 111.640112 -229.272846)
		(width 0.2032)
		(layer "F.Cu")
		(net "GND")
	)
	(segment
		(start 361.883706 -415.239962)
		(end 361.50296 -415.239962)
		(width 0.3556)
		(layer "F.Cu")
		(net "GND")
	)
	(segment
		(start 357.70058 -220.041978)
		(end 357.700834 -220.041724)
		(width 0.254)
		(layer "F.Cu")
		(net "GND")
	)
	(segment
		(start 386.474716 -285.6611)
		(end 386.474462 -285.661354)
		(width 0.2032)
		(layer "F.Cu")
		(net "GND")
	)
	(segment
		(start 113.094262 -137.799826)
		(end 112.484662 -137.799826)
		(width 0.381)
		(layer "F.Cu")
		(net "GND")
	)
	(segment
		(start 411.958282 -316.316614)
		(end 410.853382 -316.316614)
		(width 0.381)
		(layer "F.Cu")
		(net "GND")
	)
	(segment
		(start 49.959514 -271.266666)
		(end 51.064414 -271.266666)
		(width 0.381)
		(layer "F.Cu")
		(net "GND")
	)
	(segment
		(start 211.619846 -315.46673)
		(end 210.514946 -315.46673)
		(width 0.381)
		(layer "F.Cu")
		(net "GND")
	)
	(segment
		(start 122.558048 -283.497782)
		(end 122.558048 -284.033468)
		(width 0.254)
		(layer "F.Cu")
		(net "GND")
	)
	(segment
		(start 347.942916 -283.497782)
		(end 347.942916 -284.033468)
		(width 0.254)
		(layer "F.Cu")
		(net "GND")
	)
	(segment
		(start 142.346934 -17.655032)
		(end 142.346934 -16.550132)
		(width 0.3556)
		(layer "F.Cu")
		(net "GND")
	)
	(segment
		(start 348.412562 -269.66164)
		(end 348.412562 -270.197326)
		(width 0.2032)
		(layer "F.Cu")
		(net "GND")
	)
	(segment
		(start 262.519414 -227.066602)
		(end 263.624314 -227.066602)
		(width 0.381)
		(layer "F.Cu")
		(net "GND")
	)
	(segment
		(start 26.223214 -289.966654)
		(end 27.328114 -289.966654)
		(width 0.381)
		(layer "F.Cu")
		(net "GND")
	)
	(segment
		(start 109.760512 -226.017582)
		(end 109.760766 -226.017328)
		(width 0.254)
		(layer "F.Cu")
		(net "GND")
	)
	(segment
		(start 385.064762 -281.05608)
		(end 385.064762 -281.59202)
		(width 0.2032)
		(layer "F.Cu")
		(net "GND")
	)
	(segment
		(start 118.218712 -226.017582)
		(end 118.218966 -226.017328)
		(width 0.254)
		(layer "F.Cu")
		(net "GND")
	)
	(segment
		(start 130.906012 -232.250234)
		(end 130.906012 -231.714548)
		(width 0.2032)
		(layer "F.Cu")
		(net "GND")
	)
	(segment
		(start 290.355782 -198.166736)
		(end 291.460682 -198.166736)
		(width 0.381)
		(layer "F.Cu")
		(net "GND")
	)
	(segment
		(start 372.377716 -266.127992)
		(end 372.377462 -266.128246)
		(width 0.254)
		(layer "F.Cu")
		(net "GND")
	)
	(segment
		(start 124.797566 -220.041724)
		(end 124.797566 -219.506038)
		(width 0.254)
		(layer "F.Cu")
		(net "GND")
	)
	(segment
		(start 110.340648 -259.081016)
		(end 110.340648 -259.616956)
		(width 0.254)
		(layer "F.Cu")
		(net "GND")
	)
	(segment
		(start 425.940982 -289.966654)
		(end 424.836082 -289.966654)
		(width 0.381)
		(layer "F.Cu")
		(net "GND")
	)
	(segment
		(start 344.183716 -287.288986)
		(end 344.183462 -287.28924)
		(width 0.254)
		(layer "F.Cu")
		(net "GND")
	)
	(segment
		(start 385.070604 -263.686544)
		(end 385.064762 -263.686544)
		(width 0.254)
		(layer "F.Cu")
		(net "GND")
	)
	(segment
		(start 59.654186 -238.966756)
		(end 60.947046 -238.966756)
		(width 0.381)
		(layer "F.Cu")
		(net "GND")
	)
	(segment
		(start 376.96648 -238.76127)
		(end 376.96648 -238.225584)
		(width 0.2032)
		(layer "F.Cu")
		(net "GND")
	)
	(segment
		(start 343.133934 -214.344758)
		(end 343.133934 -213.732618)
		(width 0.254)
		(layer "F.Cu")
		(net "GND")
	)
	(segment
		(start 106.893614 -409.335986)
		(end 106.41584 -409.335986)
		(width 0.3556)
		(layer "F.Cu")
		(net "GND")
	)
	(segment
		(start 327.829926 -45.448728)
		(end 326.999854 -45.448728)
		(width 0.2032)
		(layer "F.Cu")
		(net "GND")
	)
	(segment
		(start 132.785866 -214.344758)
		(end 132.785866 -213.732618)
		(width 0.254)
		(layer "F.Cu")
		(net "GND")
	)
	(segment
		(start 336.195162 -257.175254)
		(end 336.195162 -256.639314)
		(width 0.2032)
		(layer "F.Cu")
		(net "GND")
	)
	(segment
		(start 202.971146 -210.916774)
		(end 204.076046 -210.916774)
		(width 0.381)
		(layer "F.Cu")
		(net "GND")
	)
	(segment
		(start 420.736014 -229.616762)
		(end 421.840914 -229.616762)
		(width 0.381)
		(layer "F.Cu")
		(net "GND")
	)
	(segment
		(start 156.25699 -13.600176)
		(end 156.25699 -12.495022)
		(width 0.3556)
		(layer "F.Cu")
		(net "GND")
	)
	(segment
		(start 184.439814 -221.116652)
		(end 185.544714 -221.116652)
		(width 0.381)
		(layer "F.Cu")
		(net "GND")
	)
	(segment
		(start 124.797312 -216.78646)
		(end 124.797312 -216.250774)
		(width 0.254)
		(layer "F.Cu")
		(net "GND")
	)
	(segment
		(start 104.701594 -266.128246)
		(end 104.701594 -265.592306)
		(width 0.254)
		(layer "F.Cu")
		(net "GND")
	)
	(segment
		(start 84.964524 -276.172676)
		(end 85.435694 -276.172676)
		(width 0.2032)
		(layer "F.Cu")
		(net "GND")
	)
	(segment
		(start 305.443382 -215.166702)
		(end 306.548282 -215.166702)
		(width 0.381)
		(layer "F.Cu")
		(net "GND")
	)
	(segment
		(start 215.719914 -196.466714)
		(end 216.824814 -196.466714)
		(width 0.381)
		(layer "F.Cu")
		(net "GND")
	)
	(segment
		(start 418.356796 -11.26998)
		(end 418.356796 -12.37488)
		(width 0.3556)
		(layer "F.Cu")
		(net "GND")
	)
	(segment
		(start 204.076046 -309.51678)
		(end 205.180946 -309.51678)
		(width 0.381)
		(layer "F.Cu")
		(net "GND")
	)
	(segment
		(start 94.364048 -286.7533)
		(end 94.364048 -287.288986)
		(width 0.254)
		(layer "F.Cu")
		(net "GND")
	)
	(segment
		(start 278.474678 -418.454078)
		(end 278.474678 -419.26129)
		(width 0.3556)
		(layer "F.Cu")
		(net "GND")
	)
	(segment
		(start 418.180012 -165.283642)
		(end 417.834572 -164.938202)
		(width 0.2032)
		(layer "F.Cu")
		(net "GND")
	)
	(segment
		(start 196.532246 -229.616762)
		(end 197.637146 -229.616762)
		(width 0.381)
		(layer "F.Cu")
		(net "GND")
	)
	(segment
		(start 34.871914 -278.916638)
		(end 33.767014 -278.916638)
		(width 0.381)
		(layer "F.Cu")
		(net "GND")
	)
	(segment
		(start 158.813246 -267.016738)
		(end 159.918146 -267.016738)
		(width 0.381)
		(layer "F.Cu")
		(net "GND")
	)
	(segment
		(start 372.267734 -233.87812)
		(end 372.26748 -233.877866)
		(width 0.254)
		(layer "F.Cu")
		(net "GND")
	)
	(segment
		(start 435.823614 -292.516814)
		(end 436.928514 -292.516814)
		(width 0.381)
		(layer "F.Cu")
		(net "GND")
	)
	(segment
		(start 43.520614 -222.816674)
		(end 42.415714 -222.816674)
		(width 0.381)
		(layer "F.Cu")
		(net "GND")
	)
	(segment
		(start 373.207534 -240.389156)
		(end 373.207534 -239.853216)
		(width 0.2032)
		(layer "F.Cu")
		(net "GND")
	)
	(segment
		(start 27.328114 -294.216582)
		(end 28.433014 -294.216582)
		(width 0.381)
		(layer "F.Cu")
		(net "GND")
	)
	(segment
		(start 418.397182 -215.166702)
		(end 417.292282 -215.166702)
		(width 0.381)
		(layer "F.Cu")
		(net "GND")
	)
	(segment
		(start 449.52666 -48.561498)
		(end 449.52666 -49.476406)
		(width 0.508)
		(layer "F.Cu")
		(net "GND")
	)
	(segment
		(start 136.184894 -258.2672)
		(end 136.184894 -258.80314)
		(width 0.254)
		(layer "F.Cu")
		(net "GND")
	)
	(segment
		(start 336.555334 -230.622602)
		(end 336.55508 -230.622348)
		(width 0.2032)
		(layer "F.Cu")
		(net "GND")
	)
	(segment
		(start 263.624314 -201.56678)
		(end 264.729214 -201.56678)
		(width 0.381)
		(layer "F.Cu")
		(net "GND")
	)
	(segment
		(start 378.846334 -240.389156)
		(end 378.84608 -240.388902)
		(width 0.2032)
		(layer "F.Cu")
		(net "GND")
	)
	(segment
		(start 356.291134 -217.600276)
		(end 356.291134 -217.064336)
		(width 0.2032)
		(layer "F.Cu")
		(net "GND")
	)
	(segment
		(start 127.616966 -231.436164)
		(end 127.616966 -230.900478)
		(width 0.2032)
		(layer "F.Cu")
		(net "GND")
	)
	(segment
		(start 175.005746 -315.46673)
		(end 173.900846 -315.46673)
		(width 0.381)
		(layer "F.Cu")
		(net "GND")
	)
	(segment
		(start 129.026666 -248.528078)
		(end 129.026412 -248.527824)
		(width 0.2032)
		(layer "F.Cu")
		(net "GND")
	)
	(segment
		(start 117.351048 -130.396488)
		(end 118.108476 -130.396488)
		(width 0.3556)
		(layer "F.Cu")
		(net "GND")
	)
	(segment
		(start 366.15878 -222.76181)
		(end 366.159034 -222.761556)
		(width 0.254)
		(layer "F.Cu")
		(net "GND")
	)
	(segment
		(start 421.840914 -246.616728)
		(end 422.945814 -246.616728)
		(width 0.381)
		(layer "F.Cu")
		(net "GND")
	)
	(segment
		(start 417.834572 -164.938202)
		(end 417.834572 -164.585904)
		(width 0.2032)
		(layer "F.Cu")
		(net "GND")
	)
	(segment
		(start 300.238414 -229.616762)
		(end 301.343314 -229.616762)
		(width 0.381)
		(layer "F.Cu")
		(net "GND")
	)
	(segment
		(start 170.457114 -286.56661)
		(end 169.352214 -286.56661)
		(width 0.381)
		(layer "F.Cu")
		(net "GND")
	)
	(segment
		(start 95.631 -92.134944)
		(end 95.123508 -92.134944)
		(width 0.3556)
		(layer "F.Cu")
		(net "GND")
	)
	(segment
		(start 285.150814 -203.266802)
		(end 286.255714 -203.266802)
		(width 0.381)
		(layer "F.Cu")
		(net "GND")
	)
	(segment
		(start 356.76078 -232.528618)
		(end 356.761034 -232.528364)
		(width 0.2032)
		(layer "F.Cu")
		(net "GND")
	)
	(segment
		(start 135.135112 -232.528618)
		(end 135.135366 -232.528364)
		(width 0.2032)
		(layer "F.Cu")
		(net "GND")
	)
	(segment
		(start 18.679414 -245.76659)
		(end 19.784314 -245.76659)
		(width 0.381)
		(layer "F.Cu")
		(net "GND")
	)
	(segment
		(start 129.606294 -272.917158)
		(end 129.606548 -273.453098)
		(width 0.2032)
		(layer "F.Cu")
		(net "GND")
	)
	(segment
		(start 135.605266 -238.225584)
		(end 135.605266 -238.761524)
		(width 0.254)
		(layer "F.Cu")
		(net "GND")
	)
	(segment
		(start 108.820712 -216.250774)
		(end 108.820966 -216.25052)
		(width 0.254)
		(layer "F.Cu")
		(net "GND")
	)
	(segment
		(start 427.126908 -123.23572)
		(end 427.733968 -122.62866)
		(width 0.381)
		(layer "F.Cu")
		(net "GND")
	)
	(segment
		(start 422.750996 -364.257336)
		(end 423.095674 -363.912658)
		(width 0.2032)
		(layer "F.Cu")
		(net "GND")
	)
	(segment
		(start 458.455014 -298.466764)
		(end 459.559914 -298.466764)
		(width 0.381)
		(layer "F.Cu")
		(net "GND")
	)
	(segment
		(start 375.197116 -257.45313)
		(end 375.197116 -257.98907)
		(width 0.2032)
		(layer "F.Cu")
		(net "GND")
	)
	(segment
		(start 38.315646 -290.816792)
		(end 37.210746 -290.816792)
		(width 0.381)
		(layer "F.Cu")
		(net "GND")
	)
	(segment
		(start 342.194134 -238.761524)
		(end 342.19388 -238.76127)
		(width 0.2032)
		(layer "F.Cu")
		(net "GND")
	)
	(segment
		(start 281.707082 -280.61666)
		(end 282.811982 -280.61666)
		(width 0.381)
		(layer "F.Cu")
		(net "GND")
	)
	(segment
		(start 62.30493 -18.252948)
		(end 62.92088 -18.252948)
		(width 0.3556)
		(layer "F.Cu")
		(net "GND")
	)
	(segment
		(start 281.707082 -233.86669)
		(end 282.811982 -233.86669)
		(width 0.381)
		(layer "F.Cu")
		(net "GND")
	)
	(segment
		(start 93.314266 -217.600276)
		(end 93.314266 -217.064336)
		(width 0.2032)
		(layer "F.Cu")
		(net "GND")
	)
	(segment
		(start 427.766988 -8.320024)
		(end 427.766988 -9.424924)
		(width 0.3556)
		(layer "F.Cu")
		(net "GND")
	)
	(segment
		(start 267.724382 -222.816674)
		(end 268.829282 -222.816674)
		(width 0.381)
		(layer "F.Cu")
		(net "GND")
	)
	(segment
		(start 354.88118 -216.250774)
		(end 354.881434 -216.25052)
		(width 0.254)
		(layer "F.Cu")
		(net "GND")
	)
	(segment
		(start 175.005746 -242.3668)
		(end 173.900846 -242.3668)
		(width 0.381)
		(layer "F.Cu")
		(net "GND")
	)
	(segment
		(start 28.638246 -393.342876)
		(end 28.028646 -393.342876)
		(width 0.3556)
		(layer "F.Cu")
		(net "GND")
	)
	(segment
		(start 373.67718 -249.342148)
		(end 373.677434 -249.341894)
		(width 0.2032)
		(layer "F.Cu")
		(net "GND")
	)
	(segment
		(start 122.917712 -223.297496)
		(end 122.917712 -222.76181)
		(width 0.254)
		(layer "F.Cu")
		(net "GND")
	)
	(segment
		(start 367.678716 -284.033468)
		(end 367.678462 -284.033722)
		(width 0.254)
		(layer "F.Cu")
		(net "GND")
	)
	(segment
		(start 267.724382 -205.816708)
		(end 268.829282 -205.816708)
		(width 0.381)
		(layer "F.Cu")
		(net "GND")
	)
	(segment
		(start 294.904414 -268.71676)
		(end 293.799514 -268.71676)
		(width 0.381)
		(layer "F.Cu")
		(net "GND")
	)
	(segment
		(start 330.79436 -51.739546)
		(end 331.065378 -51.269646)
		(width 0.2032)
		(layer "F.Cu")
		(net "GND")
	)
	(segment
		(start 11.135614 -232.166668)
		(end 12.240514 -232.166668)
		(width 0.381)
		(layer "F.Cu")
		(net "GND")
	)
	(segment
		(start 26.223214 -295.916604)
		(end 27.328114 -295.916604)
		(width 0.381)
		(layer "F.Cu")
		(net "GND")
	)
	(segment
		(start 304.338482 -226.216718)
		(end 305.443382 -226.216718)
		(width 0.381)
		(layer "F.Cu")
		(net "GND")
	)
	(segment
		(start 435.585616 -39.500556)
		(end 435.40172 -39.31666)
		(width 0.3556)
		(layer "F.Cu")
		(net "GND")
	)
	(segment
		(start 339.484716 -263.96442)
		(end 339.484716 -264.50036)
		(width 0.2032)
		(layer "F.Cu")
		(net "GND")
	)
	(segment
		(start 19.790664 -110.875826)
		(end 19.181064 -110.875826)
		(width 0.3556)
		(layer "F.Cu")
		(net "GND")
	)
	(segment
		(start 462.555082 -216.866724)
		(end 463.659982 -216.866724)
		(width 0.381)
		(layer "F.Cu")
		(net "GND")
	)
	(segment
		(start 307.782214 -248.31675)
		(end 308.887114 -248.31675)
		(width 0.381)
		(layer "F.Cu")
		(net "GND")
	)
	(segment
		(start 53.267102 -8.320024)
		(end 53.267102 -7.215124)
		(width 0.3556)
		(layer "F.Cu")
		(net "GND")
	)
	(segment
		(start 154.992324 -119.950992)
		(end 153.789126 -119.950992)
		(width 0.3556)
		(layer "F.Cu")
		(net "GND")
	)
	(segment
		(start 361.929934 -223.575626)
		(end 361.929934 -224.111566)
		(width 0.2032)
		(layer "F.Cu")
		(net "GND")
	)
	(segment
		(start 101.772466 -243.644928)
		(end 101.772212 -243.644674)
		(width 0.254)
		(layer "F.Cu")
		(net "GND")
	)
	(segment
		(start 15.684246 -208.366614)
		(end 16.789146 -208.366614)
		(width 0.381)
		(layer "F.Cu")
		(net "GND")
	)
	(segment
		(start 208.176114 -210.066636)
		(end 209.281014 -210.066636)
		(width 0.381)
		(layer "F.Cu")
		(net "GND")
	)
	(segment
		(start 130.076448 -267.219938)
		(end 130.076448 -267.755624)
		(width 0.254)
		(layer "F.Cu")
		(net "GND")
	)
	(segment
		(start 211.619846 -242.3668)
		(end 212.724746 -242.3668)
		(width 0.381)
		(layer "F.Cu")
		(net "GND")
	)
	(segment
		(start 358.280716 -280.242264)
		(end 358.280716 -280.77795)
		(width 0.254)
		(layer "F.Cu")
		(net "GND")
	)
	(segment
		(start 49.959514 -224.516696)
		(end 51.064414 -224.516696)
		(width 0.381)
		(layer "F.Cu")
		(net "GND")
	)
	(segment
		(start 93.424248 -286.7533)
		(end 93.424248 -287.288986)
		(width 0.254)
		(layer "F.Cu")
		(net "GND")
	)
	(segment
		(start 97.073466 -217.600276)
		(end 97.073466 -217.064336)
		(width 0.2032)
		(layer "F.Cu")
		(net "GND")
	)
	(segment
		(start 377.436634 -241.202972)
		(end 377.436634 -240.667286)
		(width 0.2032)
		(layer "F.Cu")
		(net "GND")
	)
	(segment
		(start 374.726962 -285.939484)
		(end 374.726962 -286.475424)
		(width 0.2032)
		(layer "F.Cu")
		(net "GND")
	)
	(segment
		(start 158.813246 -306.116736)
		(end 159.918146 -306.116736)
		(width 0.381)
		(layer "F.Cu")
		(net "GND")
	)
	(segment
		(start 30.771846 -287.416748)
		(end 31.876746 -287.416748)
		(width 0.381)
		(layer "F.Cu")
		(net "GND")
	)
	(segment
		(start 167.461946 -300.166786)
		(end 166.357046 -300.166786)
		(width 0.381)
		(layer "F.Cu")
		(net "GND")
	)
	(segment
		(start 254.975614 -240.666778)
		(end 256.080514 -240.666778)
		(width 0.381)
		(layer "F.Cu")
		(net "GND")
	)
	(segment
		(start 123.857512 -223.297496)
		(end 123.857512 -222.76181)
		(width 0.254)
		(layer "F.Cu")
		(net "GND")
	)
	(segment
		(start 433.484782 -247.466612)
		(end 434.589682 -247.466612)
		(width 0.381)
		(layer "F.Cu")
		(net "GND")
	)
	(segment
		(start 356.76078 -223.297496)
		(end 356.76078 -222.76181)
		(width 0.254)
		(layer "F.Cu")
		(net "GND")
	)
	(segment
		(start 418.397182 -278.916638)
		(end 417.292282 -278.916638)
		(width 0.381)
		(layer "F.Cu")
		(net "GND")
	)
	(segment
		(start 417.66744 -52.27701)
		(end 416.584384 -52.27701)
		(width 0.3556)
		(layer "F.Cu")
		(net "GND")
	)
	(segment
		(start 102.242366 -220.041724)
		(end 102.242366 -219.506038)
		(width 0.254)
		(layer "F.Cu")
		(net "GND")
	)
	(segment
		(start 94.364048 -275.35886)
		(end 94.364048 -275.8948)
		(width 0.2032)
		(layer "F.Cu")
		(net "GND")
	)
	(segment
		(start 326.263 -37.982144)
		(end 326.584818 -38.2905)
		(width 0.2032)
		(layer "F.Cu")
		(net "GND")
	)
	(segment
		(start 286.255714 -273.816572)
		(end 287.360614 -273.816572)
		(width 0.381)
		(layer "F.Cu")
		(net "GND")
	)
	(segment
		(start 214.615014 -267.866622)
		(end 215.719914 -267.866622)
		(width 0.381)
		(layer "F.Cu")
		(net "GND")
	)
	(segment
		(start 204.076046 -231.316784)
		(end 205.180946 -231.316784)
		(width 0.381)
		(layer "F.Cu")
		(net "GND")
	)
	(segment
		(start 382.245362 -259.894832)
		(end 382.245362 -260.430518)
		(width 0.2032)
		(layer "F.Cu")
		(net "GND")
	)
	(segment
		(start 289.250882 -232.166668)
		(end 290.355782 -232.166668)
		(width 0.381)
		(layer "F.Cu")
		(net "GND")
	)
	(segment
		(start 89.664794 -272.103342)
		(end 89.664794 -272.639282)
		(width 0.2032)
		(layer "F.Cu")
		(net "GND")
	)
	(segment
		(start 296.794682 -284.866588)
		(end 297.899582 -284.866588)
		(width 0.381)
		(layer "F.Cu")
		(net "GND")
	)
	(segment
		(start 22.123146 -216.016586)
		(end 23.228046 -216.016586)
		(width 0.381)
		(layer "F.Cu")
		(net "GND")
	)
	(segment
		(start 52.298346 -225.36658)
		(end 53.403246 -225.36658)
		(width 0.381)
		(layer "F.Cu")
		(net "GND")
	)
	(segment
		(start 166.357046 -301.866808)
		(end 165.252146 -301.866808)
		(width 0.381)
		(layer "F.Cu")
		(net "GND")
	)
	(segment
		(start 254.975614 -268.71676)
		(end 256.080514 -268.71676)
		(width 0.381)
		(layer "F.Cu")
		(net "GND")
	)
	(segment
		(start 282.811982 -294.216582)
		(end 283.916882 -294.216582)
		(width 0.381)
		(layer "F.Cu")
		(net "GND")
	)
	(segment
		(start 171.666916 -13.600176)
		(end 171.666916 -12.495022)
		(width 0.3556)
		(layer "F.Cu")
		(net "GND")
	)
	(segment
		(start 111.170466 -232.250488)
		(end 111.170212 -232.250234)
		(width 0.254)
		(layer "F.Cu")
		(net "GND")
	)
	(segment
		(start 119.628666 -222.48368)
		(end 119.628666 -221.94774)
		(width 0.254)
		(layer "F.Cu")
		(net "GND")
	)
	(segment
		(start 106.941112 -229.808786)
		(end 106.941366 -229.808532)
		(width 0.2032)
		(layer "F.Cu")
		(net "GND")
	)
	(segment
		(start 158.813246 -248.31675)
		(end 157.708346 -248.31675)
		(width 0.381)
		(layer "F.Cu")
		(net "GND")
	)
	(segment
		(start 422.17848 -153.614628)
		(end 422.074594 -153.510742)
		(width 0.254)
		(layer "F.Cu")
		(net "GND")
	)
	(segment
		(start 197.429882 -80.617568)
		(end 197.429882 -81.506568)
		(width 0.3556)
		(layer "F.Cu")
		(net "GND")
	)
	(segment
		(start 83.338924 -153.021792)
		(end 82.322924 -153.021792)
		(width 0.3556)
		(layer "F.Cu")
		(net "GND")
	)
	(segment
		(start 113.519712 -235.78439)
		(end 113.52022 -235.783882)
		(width 0.254)
		(layer "F.Cu")
		(net "GND")
	)
	(segment
		(start 90.964766 -249.341894)
		(end 90.964766 -248.806208)
		(width 0.2032)
		(layer "F.Cu")
		(net "GND")
	)
	(segment
		(start 96.243394 -267.220192)
		(end 96.243394 -267.755878)
		(width 0.2032)
		(layer "F.Cu")
		(net "GND")
	)
	(segment
		(start 105.171494 -281.05608)
		(end 105.171748 -281.59202)
		(width 0.2032)
		(layer "F.Cu")
		(net "GND")
	)
	(segment
		(start 166.357046 -268.71676)
		(end 165.252146 -268.71676)
		(width 0.381)
		(layer "F.Cu")
		(net "GND")
	)
	(segment
		(start 321.863466 -23.551896)
		(end 321.21348 -23.551896)
		(width 0.3556)
		(layer "F.Cu")
		(net "GND")
	)
	(segment
		(start 334.898746 -57.605168)
		(end 333.89824 -57.605168)
		(width 0.2032)
		(layer "F.Cu")
		(net "GND")
	)
	(segment
		(start 367.09858 -220.041978)
		(end 367.098834 -220.041724)
		(width 0.254)
		(layer "F.Cu")
		(net "GND")
	)
	(segment
		(start 136.545066 -240.389156)
		(end 136.545066 -239.85347)
		(width 0.254)
		(layer "F.Cu")
		(net "GND")
	)
	(segment
		(start 360.51998 -223.297496)
		(end 360.51998 -222.76181)
		(width 0.254)
		(layer "F.Cu")
		(net "GND")
	)
	(segment
		(start 34.871914 -239.81664)
		(end 35.976814 -239.81664)
		(width 0.381)
		(layer "F.Cu")
		(net "GND")
	)
	(segment
		(start 349.352362 -262.058404)
		(end 349.352616 -262.058658)
		(width 0.254)
		(layer "F.Cu")
		(net "GND")
	)
	(segment
		(start 159.918146 -223.666558)
		(end 158.813246 -223.666558)
		(width 0.381)
		(layer "F.Cu")
		(net "GND")
	)
	(segment
		(start 104.701848 -279.150064)
		(end 104.701594 -279.150318)
		(width 0.2032)
		(layer "F.Cu")
		(net "GND")
	)
	(segment
		(start 98.013266 -246.900446)
		(end 98.013012 -246.900192)
		(width 0.2032)
		(layer "F.Cu")
		(net "GND")
	)
	(segment
		(start 360.050334 -217.064336)
		(end 360.050334 -217.600276)
		(width 0.2032)
		(layer "F.Cu")
		(net "GND")
	)
	(segment
		(start 410.853382 -277.216616)
		(end 411.958282 -277.216616)
		(width 0.381)
		(layer "F.Cu")
		(net "GND")
	)
	(segment
		(start 12.240514 -221.116652)
		(end 13.345414 -221.116652)
		(width 0.381)
		(layer "F.Cu")
		(net "GND")
	)
	(segment
		(start 367.678716 -280.242264)
		(end 367.678716 -280.77795)
		(width 0.254)
		(layer "F.Cu")
		(net "GND")
	)
	(segment
		(start 127.147066 -224.111566)
		(end 127.147066 -223.575626)
		(width 0.2032)
		(layer "F.Cu")
		(net "GND")
	)
	(segment
		(start 162.913314 -297.616626)
		(end 161.808414 -297.616626)
		(width 0.381)
		(layer "F.Cu")
		(net "GND")
	)
	(segment
		(start 289.250882 -249.166634)
		(end 290.355782 -249.166634)
		(width 0.381)
		(layer "F.Cu")
		(net "GND")
	)
	(segment
		(start 12.240514 -271.266666)
		(end 13.345414 -271.266666)
		(width 0.381)
		(layer "F.Cu")
		(net "GND")
	)
	(segment
		(start 251.16409 -47.102522)
		(end 251.139706 -47.078138)
		(width 0.3556)
		(layer "F.Cu")
		(net "GND")
	)
	(segment
		(start 429.384714 -246.616728)
		(end 430.489614 -246.616728)
		(width 0.381)
		(layer "F.Cu")
		(net "GND")
	)
	(segment
		(start 263.624314 -246.616728)
		(end 264.729214 -246.616728)
		(width 0.381)
		(layer "F.Cu")
		(net "GND")
	)
	(segment
		(start 339.374734 -232.250488)
		(end 339.37448 -232.250234)
		(width 0.2032)
		(layer "F.Cu")
		(net "GND")
	)
	(segment
		(start 185.544714 -306.96662)
		(end 184.439814 -306.96662)
		(width 0.381)
		(layer "F.Cu")
		(net "GND")
	)
	(segment
		(start 436.928514 -203.266802)
		(end 438.033414 -203.266802)
		(width 0.381)
		(layer "F.Cu")
		(net "GND")
	)
	(segment
		(start 292.74643 -411.21584)
		(end 292.74643 -410.68625)
		(width 0.3556)
		(layer "F.Cu")
		(net "GND")
	)
	(segment
		(start 347.36278 -216.78646)
		(end 347.36278 -216.250774)
		(width 0.254)
		(layer "F.Cu")
		(net "GND")
	)
	(segment
		(start 444.472314 -248.31675)
		(end 445.577214 -248.31675)
		(width 0.381)
		(layer "F.Cu")
		(net "GND")
	)
	(segment
		(start 57.503314 -294.216582)
		(end 58.608214 -294.216582)
		(width 0.381)
		(layer "F.Cu")
		(net "GND")
	)
	(segment
		(start 132.315966 -239.575086)
		(end 132.315966 -239.0394)
		(width 0.2032)
		(layer "F.Cu")
		(net "GND")
	)
	(segment
		(start 361.45978 -216.78646)
		(end 361.45978 -216.25052)
		(width 0.254)
		(layer "F.Cu")
		(net "GND")
	)
	(segment
		(start 380.25578 -222.76181)
		(end 380.256034 -222.761556)
		(width 0.254)
		(layer "F.Cu")
		(net "GND")
	)
	(segment
		(start 92.014294 -279.428194)
		(end 92.014294 -279.96388)
		(width 0.254)
		(layer "F.Cu")
		(net "GND")
	)
	(segment
		(start 175.552862 -32.351472)
		(end 176.694084 -31.21025)
		(width 0.254)
		(layer "F.Cu")
		(net "GND")
	)
	(segment
		(start 378.956316 -259.081016)
		(end 378.956316 -259.093462)
		(width 0.2032)
		(layer "F.Cu")
		(net "GND")
	)
	(segment
		(start 296.794682 -267.866622)
		(end 297.899582 -267.866622)
		(width 0.381)
		(layer "F.Cu")
		(net "GND")
	)
	(segment
		(start 353.941634 -229.808532)
		(end 353.941634 -229.272846)
		(width 0.2032)
		(layer "F.Cu")
		(net "GND")
	)
	(segment
		(start 419.502082 -247.466612)
		(end 418.397182 -247.466612)
		(width 0.381)
		(layer "F.Cu")
		(net "GND")
	)
	(segment
		(start 373.317516 -281.869896)
		(end 373.317516 -282.405582)
		(width 0.254)
		(layer "F.Cu")
		(net "GND")
	)
	(segment
		(start 60.947046 -317.166752)
		(end 62.051946 -317.166752)
		(width 0.381)
		(layer "F.Cu")
		(net "GND")
	)
	(segment
		(start 165.252146 -283.166566)
		(end 166.357046 -283.166566)
		(width 0.381)
		(layer "F.Cu")
		(net "GND")
	)
	(segment
		(start 119.249952 -411.120082)
		(end 119.23903 -411.131004)
		(width 0.3556)
		(layer "F.Cu")
		(net "GND")
	)
	(segment
		(start 158.813246 -279.766776)
		(end 159.918146 -279.766776)
		(width 0.381)
		(layer "F.Cu")
		(net "GND")
	)
	(segment
		(start 289.250882 -269.566644)
		(end 290.355782 -269.566644)
		(width 0.381)
		(layer "F.Cu")
		(net "GND")
	)
	(segment
		(start 278.711914 -242.3668)
		(end 279.816814 -242.3668)
		(width 0.381)
		(layer "F.Cu")
		(net "GND")
	)
	(segment
		(start 167.461946 -287.213548)
		(end 167.258746 -287.416748)
		(width 0.381)
		(layer "F.Cu")
		(net "GND")
	)
	(segment
		(start 65.047114 -235.566712)
		(end 66.367914 -235.566712)
		(width 0.381)
		(layer "F.Cu")
		(net "GND")
	)
	(segment
		(start 52.082446 -313.766708)
		(end 53.403246 -313.766708)
		(width 0.381)
		(layer "F.Cu")
		(net "GND")
	)
	(segment
		(start 120.678448 -280.242264)
		(end 120.678448 -280.77795)
		(width 0.254)
		(layer "F.Cu")
		(net "GND")
	)
	(segment
		(start 293.799514 -289.11677)
		(end 292.694614 -289.11677)
		(width 0.381)
		(layer "F.Cu")
		(net "GND")
	)
	(segment
		(start 131.486148 -282.68422)
		(end 131.486148 -283.219906)
		(width 0.254)
		(layer "F.Cu")
		(net "GND")
	)
	(segment
		(start 368.97818 -234.69219)
		(end 368.97818 -234.15625)
		(width 0.254)
		(layer "F.Cu")
		(net "GND")
	)
	(segment
		(start 361.45978 -249.342148)
		(end 361.45978 -248.806462)
		(width 0.254)
		(layer "F.Cu")
		(net "GND")
	)
	(segment
		(start 175.005746 -251.716794)
		(end 173.900846 -251.716794)
		(width 0.381)
		(layer "F.Cu")
		(net "GND")
	)
	(segment
		(start 398.446752 -11.26998)
		(end 398.446752 -12.37488)
		(width 0.3556)
		(layer "F.Cu")
		(net "GND")
	)
	(segment
		(start 66.380614 -54.361588)
		(end 66.71183 -54.361588)
		(width 0.3556)
		(layer "F.Cu")
		(net "GND")
	)
	(segment
		(start 210.099656 -67.20332)
		(end 210.73872 -67.20332)
		(width 0.3556)
		(layer "F.Cu")
		(net "GND")
	)
	(segment
		(start 27.328114 -247.466612)
		(end 28.433014 -247.466612)
		(width 0.381)
		(layer "F.Cu")
		(net "GND")
	)
	(segment
		(start 61.52261 -37.957252)
		(end 61.52261 -38.554152)
		(width 0.3556)
		(layer "F.Cu")
		(net "GND")
	)
	(segment
		(start 355.461316 -282.405582)
		(end 355.461062 -282.405836)
		(width 0.254)
		(layer "F.Cu")
		(net "GND")
	)
	(segment
		(start 286.255714 -298.466764)
		(end 287.360614 -298.466764)
		(width 0.381)
		(layer "F.Cu")
		(net "GND")
	)
	(segment
		(start 215.719914 -308.666642)
		(end 216.824814 -308.666642)
		(width 0.381)
		(layer "F.Cu")
		(net "GND")
	)
	(segment
		(start 214.615014 -278.916638)
		(end 215.719914 -278.916638)
		(width 0.381)
		(layer "F.Cu")
		(net "GND")
	)
	(segment
		(start 208.176114 -233.86669)
		(end 209.281014 -233.86669)
		(width 0.381)
		(layer "F.Cu")
		(net "GND")
	)
	(segment
		(start 281.707082 -226.216718)
		(end 282.811982 -226.216718)
		(width 0.381)
		(layer "F.Cu")
		(net "GND")
	)
	(segment
		(start 126.317248 -254.197612)
		(end 126.317248 -254.733552)
		(width 0.2032)
		(layer "F.Cu")
		(net "GND")
	)
	(segment
		(start 132.315712 -241.203226)
		(end 132.315712 -240.667286)
		(width 0.2032)
		(layer "F.Cu")
		(net "GND")
	)
	(segment
		(start 208.176114 -284.866588)
		(end 209.281014 -284.866588)
		(width 0.381)
		(layer "F.Cu")
		(net "GND")
	)
	(segment
		(start 8.140446 -313.766708)
		(end 9.245346 -313.766708)
		(width 0.381)
		(layer "F.Cu")
		(net "GND")
	)
	(segment
		(start 339.374734 -233.87812)
		(end 339.374734 -233.34218)
		(width 0.2032)
		(layer "F.Cu")
		(net "GND")
	)
	(segment
		(start 380.365762 -289.195002)
		(end 380.365762 -289.807142)
		(width 0.2032)
		(layer "F.Cu")
		(net "GND")
	)
	(segment
		(start 185.399172 -21.580856)
		(end 185.399172 -22.097492)
		(width 0.4572)
		(layer "F.Cu")
		(net "GND")
	)
	(segment
		(start 109.760512 -226.553268)
		(end 109.760512 -226.017582)
		(width 0.254)
		(layer "F.Cu")
		(net "GND")
	)
	(segment
		(start 294.904414 -220.266768)
		(end 293.799514 -220.266768)
		(width 0.381)
		(layer "F.Cu")
		(net "GND")
	)
	(segment
		(start 355.930962 -273.452844)
		(end 355.931216 -273.453098)
		(width 0.2032)
		(layer "F.Cu")
		(net "GND")
	)
	(segment
		(start 304.338482 -196.466714)
		(end 305.443382 -196.466714)
		(width 0.381)
		(layer "F.Cu")
		(net "GND")
	)
	(segment
		(start 345.15171 -50.59172)
		(end 345.554554 -49.950878)
		(width 0.1778)
		(layer "F.Cu")
		(net "GND")
	)
	(segment
		(start 340.894162 -276.172676)
		(end 340.894162 -276.708362)
		(width 0.2032)
		(layer "F.Cu")
		(net "GND")
	)
	(segment
		(start 420.991538 -173.654974)
		(end 421.618156 -173.654974)
		(width 0.381)
		(layer "F.Cu")
		(net "GND")
	)
	(segment
		(start 7.035546 -227.066602)
		(end 8.140446 -227.066602)
		(width 0.381)
		(layer "F.Cu")
		(net "GND")
	)
	(segment
		(start 354.88118 -226.553268)
		(end 354.88118 -226.017582)
		(width 0.254)
		(layer "F.Cu")
		(net "GND")
	)
	(segment
		(start 428.279814 -214.316564)
		(end 429.384714 -214.316564)
		(width 0.381)
		(layer "F.Cu")
		(net "GND")
	)
	(segment
		(start 331.608176 -45.630846)
		(end 331.880718 -46.100746)
		(width 0.2032)
		(layer "F.Cu")
		(net "GND")
	)
	(segment
		(start 374.827292 -338.951316)
		(end 375.17959 -338.951316)
		(width 0.2032)
		(layer "F.Cu")
		(net "GND")
	)
	(segment
		(start 371.437916 -283.497782)
		(end 371.437916 -284.033468)
		(width 0.254)
		(layer "F.Cu")
		(net "GND")
	)
	(segment
		(start 347.214698 -57.954926)
		(end 346.384626 -57.954926)
		(width 0.2032)
		(layer "F.Cu")
		(net "GND")
	)
	(segment
		(start 459.559914 -287.416748)
		(end 460.664814 -287.416748)
		(width 0.381)
		(layer "F.Cu")
		(net "GND")
	)
	(segment
		(start 347.472762 -255.547368)
		(end 347.473016 -255.547622)
		(width 0.2032)
		(layer "F.Cu")
		(net "GND")
	)
	(segment
		(start 379.896116 -257.45313)
		(end 379.896116 -257.98907)
		(width 0.2032)
		(layer "F.Cu")
		(net "GND")
	)
	(segment
		(start 278.711914 -306.116736)
		(end 277.607014 -306.116736)
		(width 0.381)
		(layer "F.Cu")
		(net "GND")
	)
	(segment
		(start 77.746098 -144.708372)
		(end 77.746098 -145.206212)
		(width 0.3556)
		(layer "F.Cu")
		(net "GND")
	)
	(segment
		(start 308.887114 -289.11677)
		(end 309.992014 -289.11677)
		(width 0.381)
		(layer "F.Cu")
		(net "GND")
	)
	(segment
		(start 96.17583 -57.241948)
		(end 95.56623 -57.241948)
		(width 0.3556)
		(layer "F.Cu")
		(net "GND")
	)
	(segment
		(start 42.415714 -295.916604)
		(end 41.310814 -295.916604)
		(width 0.381)
		(layer "F.Cu")
		(net "GND")
	)
	(segment
		(start 346.063316 -265.592306)
		(end 346.063062 -265.592306)
		(width 0.254)
		(layer "F.Cu")
		(net "GND")
	)
	(segment
		(start 373.67718 -226.553268)
		(end 373.67718 -226.017582)
		(width 0.254)
		(layer "F.Cu")
		(net "GND")
	)
	(segment
		(start 463.659982 -196.466714)
		(end 464.764882 -196.466714)
		(width 0.381)
		(layer "F.Cu")
		(net "GND")
	)
	(segment
		(start 307.3146 -62.775592)
		(end 306.63388 -62.775592)
		(width 0.381)
		(layer "F.Cu")
		(net "GND")
	)
	(segment
		(start 376.496834 -247.714008)
		(end 376.496834 -247.178322)
		(width 0.2032)
		(layer "F.Cu")
		(net "GND")
	)
	(segment
		(start 138.534648 -272.103342)
		(end 139.004548 -271.825212)
		(width 0.254)
		(layer "F.Cu")
		(net "GND")
	)
	(segment
		(start 348.882716 -261.244588)
		(end 348.882462 -261.244842)
		(width 0.254)
		(layer "F.Cu")
		(net "GND")
	)
	(segment
		(start 60.947046 -301.866808)
		(end 62.051946 -301.866808)
		(width 0.381)
		(layer "F.Cu")
		(net "GND")
	)
	(segment
		(start 128.556512 -216.78646)
		(end 128.556512 -216.250774)
		(width 0.254)
		(layer "F.Cu")
		(net "GND")
	)
	(segment
		(start 305.443382 -213.46668)
		(end 306.548282 -213.46668)
		(width 0.381)
		(layer "F.Cu")
		(net "GND")
	)
	(segment
		(start 276.373082 -291.666676)
		(end 275.268182 -291.666676)
		(width 0.381)
		(layer "F.Cu")
		(net "GND")
	)
	(segment
		(start 130.345942 -103.81996)
		(end 130.345942 -104.62387)
		(width 0.254)
		(layer "F.Cu")
		(net "GND")
	)
	(segment
		(start 212.724746 -295.06672)
		(end 211.619846 -295.06672)
		(width 0.381)
		(layer "F.Cu")
		(net "GND")
	)
	(segment
		(start 443.367414 -250.016772)
		(end 444.472314 -250.016772)
		(width 0.381)
		(layer "F.Cu")
		(net "GND")
	)
	(segment
		(start 418.397182 -219.41663)
		(end 417.082732 -219.41663)
		(width 0.381)
		(layer "F.Cu")
		(net "GND")
	)
	(segment
		(start 276.373082 -284.866588)
		(end 275.268182 -284.866588)
		(width 0.381)
		(layer "F.Cu")
		(net "GND")
	)
	(segment
		(start 338.90458 -239.57534)
		(end 338.904834 -239.0394)
		(width 0.2032)
		(layer "F.Cu")
		(net "GND")
	)
	(segment
		(start 311.882282 -211.766658)
		(end 312.987182 -211.766658)
		(width 0.381)
		(layer "F.Cu")
		(net "GND")
	)
	(segment
		(start 337.604862 -288.381186)
		(end 337.604862 -288.916872)
		(width 0.254)
		(layer "F.Cu")
		(net "GND")
	)
	(segment
		(start 211.619846 -281.466798)
		(end 210.514946 -281.466798)
		(width 0.381)
		(layer "F.Cu")
		(net "GND")
	)
	(segment
		(start 356.401116 -272.639028)
		(end 356.400862 -272.639282)
		(width 0.2032)
		(layer "F.Cu")
		(net "GND")
	)
	(segment
		(start 106.471212 -233.877866)
		(end 106.471212 -233.34218)
		(width 0.2032)
		(layer "F.Cu")
		(net "GND")
	)
	(segment
		(start 412.20263 -238.116618)
		(end 410.853382 -238.116618)
		(width 0.381)
		(layer "F.Cu")
		(net "GND")
	)
	(segment
		(start 335.14538 -222.76181)
		(end 335.145634 -222.761556)
		(width 0.2032)
		(layer "F.Cu")
		(net "GND")
	)
	(segment
		(start 126.207266 -228.45903)
		(end 126.207266 -228.99497)
		(width 0.2032)
		(layer "F.Cu")
		(net "GND")
	)
	(segment
		(start 53.403246 -229.616762)
		(end 54.508146 -229.616762)
		(width 0.381)
		(layer "F.Cu")
		(net "GND")
	)
	(segment
		(start 361.569762 -279.428194)
		(end 361.569762 -279.964134)
		(width 0.254)
		(layer "F.Cu")
		(net "GND")
	)
	(segment
		(start 380.25578 -241.203226)
		(end 380.25578 -240.667286)
		(width 0.2032)
		(layer "F.Cu")
		(net "GND")
	)
	(segment
		(start 93.783912 -216.78646)
		(end 93.783912 -216.250774)
		(width 0.254)
		(layer "F.Cu")
		(net "GND")
	)
	(segment
		(start 353.00158 -220.041978)
		(end 353.001834 -220.041724)
		(width 0.254)
		(layer "F.Cu")
		(net "GND")
	)
	(segment
		(start 260.180582 -297.616626)
		(end 259.075682 -297.616626)
		(width 0.381)
		(layer "F.Cu")
		(net "GND")
	)
	(segment
		(start 311.666382 -207.51673)
		(end 312.987182 -207.51673)
		(width 0.381)
		(layer "F.Cu")
		(net "GND")
	)
	(segment
		(start 332.897734 -57.605168)
		(end 331.897482 -57.605168)
		(width 0.2032)
		(layer "F.Cu")
		(net "GND")
	)
	(segment
		(start 236.599984 -51.565048)
		(end 237.615984 -51.565048)
		(width 0.381)
		(layer "F.Cu")
		(net "GND")
	)
	(segment
		(start 429.566832 -8.320024)
		(end 429.566832 -9.424924)
		(width 0.3556)
		(layer "F.Cu")
		(net "GND")
	)
	(segment
		(start 170.457114 -275.516594)
		(end 171.765214 -275.516594)
		(width 0.381)
		(layer "F.Cu")
		(net "GND")
	)
	(segment
		(start 459.559914 -283.166566)
		(end 460.664814 -283.166566)
		(width 0.381)
		(layer "F.Cu")
		(net "GND")
	)
	(segment
		(start 42.415714 -314.616592)
		(end 41.310814 -314.616592)
		(width 0.381)
		(layer "F.Cu")
		(net "GND")
	)
	(segment
		(start 278.711914 -278.066754)
		(end 279.816814 -278.066754)
		(width 0.381)
		(layer "F.Cu")
		(net "GND")
	)
	(segment
		(start 421.840914 -238.966756)
		(end 422.945814 -238.966756)
		(width 0.381)
		(layer "F.Cu")
		(net "GND")
	)
	(segment
		(start 452.016114 -227.066602)
		(end 450.911214 -227.066602)
		(width 0.381)
		(layer "F.Cu")
		(net "GND")
	)
	(segment
		(start 337.299808 -50.450496)
		(end 336.899758 -50.050446)
		(width 0.2032)
		(layer "F.Cu")
		(net "GND")
	)
	(segment
		(start 457.221082 -312.91657)
		(end 456.116182 -312.91657)
		(width 0.381)
		(layer "F.Cu")
		(net "GND")
	)
	(segment
		(start 456.116182 -221.116652)
		(end 455.011282 -221.116652)
		(width 0.381)
		(layer "F.Cu")
		(net "GND")
	)
	(segment
		(start 210.514946 -273.816572)
		(end 211.619846 -273.816572)
		(width 0.381)
		(layer "F.Cu")
		(net "GND")
	)
	(segment
		(start 400.24685 -8.320024)
		(end 400.24685 -7.215124)
		(width 0.3556)
		(layer "F.Cu")
		(net "GND")
	)
	(segment
		(start 230.984298 -56.965088)
		(end 232.000044 -56.965088)
		(width 0.381)
		(layer "F.Cu")
		(net "GND")
	)
	(segment
		(start 52.298346 -227.066602)
		(end 53.403246 -227.066602)
		(width 0.381)
		(layer "F.Cu")
		(net "GND")
	)
	(segment
		(start 181.444646 -203.266802)
		(end 182.549546 -203.266802)
		(width 0.381)
		(layer "F.Cu")
		(net "GND")
	)
	(segment
		(start 101.302312 -244.458744)
		(end 101.302312 -243.922804)
		(width 0.2032)
		(layer "F.Cu")
		(net "GND")
	)
	(segment
		(start 113.269776 -92.329762)
		(end 113.269776 -91.199462)
		(width 0.3556)
		(layer "F.Cu")
		(net "GND")
	)
	(segment
		(start 435.823614 -261.916672)
		(end 436.928514 -261.916672)
		(width 0.381)
		(layer "F.Cu")
		(net "GND")
	)
	(segment
		(start 216.810844 -28.015184)
		(end 214.087456 -28.015184)
		(width 0.3556)
		(layer "F.Cu")
		(net "GND")
	)
	(segment
		(start 439.923682 -245.76659)
		(end 441.028582 -245.76659)
		(width 0.381)
		(layer "F.Cu")
		(net "GND")
	)
	(segment
		(start 445.363092 -12.37488)
		(end 445.361822 -12.37361)
		(width 0.3556)
		(layer "F.Cu")
		(net "GND")
	)
	(segment
		(start 102.242112 -223.297496)
		(end 102.242112 -222.76181)
		(width 0.254)
		(layer "F.Cu")
		(net "GND")
	)
	(segment
		(start 428.279814 -281.466798)
		(end 429.384714 -281.466798)
		(width 0.381)
		(layer "F.Cu")
		(net "GND")
	)
	(segment
		(start 30.771846 -304.416714)
		(end 31.876746 -304.416714)
		(width 0.381)
		(layer "F.Cu")
		(net "GND")
	)
	(segment
		(start 256.080514 -210.916774)
		(end 257.185414 -210.916774)
		(width 0.381)
		(layer "F.Cu")
		(net "GND")
	)
	(segment
		(start 350.762316 -287.288986)
		(end 350.762062 -287.28924)
		(width 0.254)
		(layer "F.Cu")
		(net "GND")
	)
	(segment
		(start 425.940982 -250.866656)
		(end 427.045882 -250.866656)
		(width 0.381)
		(layer "F.Cu")
		(net "GND")
	)
	(segment
		(start 59.842146 -307.816758)
		(end 60.947046 -307.816758)
		(width 0.381)
		(layer "F.Cu")
		(net "GND")
	)
	(segment
		(start 337.495134 -230.622602)
		(end 337.49488 -230.622348)
		(width 0.2032)
		(layer "F.Cu")
		(net "GND")
	)
	(segment
		(start 350.1517 -30.120844)
		(end 350.1517 -28.115768)
		(width 0.3556)
		(layer "F.Cu")
		(net "GND")
	)
	(segment
		(start 409.748482 -200.716642)
		(end 410.853382 -200.716642)
		(width 0.381)
		(layer "F.Cu")
		(net "GND")
	)
	(segment
		(start 381.305562 -281.05608)
		(end 381.305562 -281.591512)
		(width 0.254)
		(layer "F.Cu")
		(net "GND")
	)
	(segment
		(start 177.108104 -46.800008)
		(end 178.289204 -46.800008)
		(width 0.254)
		(layer "F.Cu")
		(net "GND")
	)
	(segment
		(start 60.947046 -233.016806)
		(end 62.051946 -233.016806)
		(width 0.381)
		(layer "F.Cu")
		(net "GND")
	)
	(segment
		(start 212.724746 -304.416714)
		(end 211.619846 -304.416714)
		(width 0.381)
		(layer "F.Cu")
		(net "GND")
	)
	(segment
		(start 65.047114 -289.966654)
		(end 66.152014 -289.966654)
		(width 0.381)
		(layer "F.Cu")
		(net "GND")
	)
	(segment
		(start 164.018214 -247.466612)
		(end 162.913314 -247.466612)
		(width 0.381)
		(layer "F.Cu")
		(net "GND")
	)
	(segment
		(start 204.076046 -317.166752)
		(end 205.180946 -317.166752)
		(width 0.381)
		(layer "F.Cu")
		(net "GND")
	)
	(segment
		(start 307.782214 -263.616694)
		(end 308.887114 -263.616694)
		(width 0.381)
		(layer "F.Cu")
		(net "GND")
	)
	(segment
		(start 14.579346 -220.266768)
		(end 15.684246 -220.266768)
		(width 0.381)
		(layer "F.Cu")
		(net "GND")
	)
	(segment
		(start 459.559914 -281.466798)
		(end 460.664814 -281.466798)
		(width 0.381)
		(layer "F.Cu")
		(net "GND")
	)
	(segment
		(start 456.116182 -200.716642)
		(end 455.011282 -200.716642)
		(width 0.381)
		(layer "F.Cu")
		(net "GND")
	)
	(segment
		(start 158.813246 -311.216802)
		(end 157.708346 -311.216802)
		(width 0.381)
		(layer "F.Cu")
		(net "GND")
	)
	(segment
		(start 377.076716 -261.244588)
		(end 377.076462 -261.244842)
		(width 0.2032)
		(layer "F.Cu")
		(net "GND")
	)
	(segment
		(start 348.882716 -287.288986)
		(end 348.882462 -287.28924)
		(width 0.254)
		(layer "F.Cu")
		(net "GND")
	)
	(segment
		(start 375.666762 -258.2672)
		(end 375.666762 -258.802886)
		(width 0.2032)
		(layer "F.Cu")
		(net "GND")
	)
	(segment
		(start 158.813246 -261.916672)
		(end 157.708346 -261.916672)
		(width 0.381)
		(layer "F.Cu")
		(net "GND")
	)
	(segment
		(start 131.375912 -226.017582)
		(end 131.376166 -226.017328)
		(width 0.254)
		(layer "F.Cu")
		(net "GND")
	)
	(segment
		(start 267.724382 -232.166668)
		(end 268.829282 -232.166668)
		(width 0.381)
		(layer "F.Cu")
		(net "GND")
	)
	(segment
		(start 202.971146 -234.716574)
		(end 204.076046 -234.716574)
		(width 0.381)
		(layer "F.Cu")
		(net "GND")
	)
	(segment
		(start 119.738648 -286.7533)
		(end 119.738648 -287.28924)
		(width 0.254)
		(layer "F.Cu")
		(net "GND")
	)
	(segment
		(start 442.171074 -124.051568)
		(end 441.776104 -123.656598)
		(width 0.381)
		(layer "F.Cu")
		(net "GND")
	)
	(segment
		(start 281.707082 -210.066636)
		(end 282.811982 -210.066636)
		(width 0.381)
		(layer "F.Cu")
		(net "GND")
	)
	(segment
		(start 428.279814 -246.616728)
		(end 429.384714 -246.616728)
		(width 0.381)
		(layer "F.Cu")
		(net "GND")
	)
	(segment
		(start 384.649726 -78.350618)
		(end 384.609848 -78.31074)
		(width 0.254)
		(layer "F.Cu")
		(net "GND")
	)
	(segment
		(start 358.170734 -245.27256)
		(end 358.170734 -244.73662)
		(width 0.254)
		(layer "F.Cu")
		(net "GND")
	)
	(segment
		(start 333.735934 -250.155964)
		(end 333.463392 -250.428506)
		(width 0.2032)
		(layer "F.Cu")
		(net "GND")
	)
	(segment
		(start 384.595116 -285.125414)
		(end 384.595116 -285.6611)
		(width 0.2032)
		(layer "F.Cu")
		(net "GND")
	)
	(segment
		(start 432.379882 -200.716642)
		(end 433.484782 -200.716642)
		(width 0.381)
		(layer "F.Cu")
		(net "GND")
	)
	(segment
		(start 204.076046 -283.166566)
		(end 205.180946 -283.166566)
		(width 0.381)
		(layer "F.Cu")
		(net "GND")
	)
	(segment
		(start 337.495134 -225.203512)
		(end 337.49488 -225.203258)
		(width 0.2032)
		(layer "F.Cu")
		(net "GND")
	)
	(segment
		(start 188.988446 -242.3668)
		(end 187.883546 -242.3668)
		(width 0.381)
		(layer "F.Cu")
		(net "GND")
	)
	(segment
		(start 63.942214 -213.46668)
		(end 65.047114 -213.46668)
		(width 0.381)
		(layer "F.Cu")
		(net "GND")
	)
	(segment
		(start 383.185162 -255.011682)
		(end 383.185162 -255.547622)
		(width 0.2032)
		(layer "F.Cu")
		(net "GND")
	)
	(segment
		(start 215.719914 -200.716642)
		(end 216.824814 -200.716642)
		(width 0.381)
		(layer "F.Cu")
		(net "GND")
	)
	(segment
		(start 425.940982 -205.816708)
		(end 427.045882 -205.816708)
		(width 0.381)
		(layer "F.Cu")
		(net "GND")
	)
	(segment
		(start 136.782302 -117.536976)
		(end 136.68248 -117.636798)
		(width 0.3556)
		(layer "F.Cu")
		(net "GND")
	)
	(segment
		(start 368.148362 -271.289272)
		(end 368.148616 -271.825212)
		(width 0.2032)
		(layer "F.Cu")
		(net "GND")
	)
	(segment
		(start 39.420546 -244.916706)
		(end 38.315646 -244.916706)
		(width 0.381)
		(layer "F.Cu")
		(net "GND")
	)
	(segment
		(start 372.26748 -240.388902)
		(end 372.26748 -239.853216)
		(width 0.2032)
		(layer "F.Cu")
		(net "GND")
	)
	(segment
		(start 121.148094 -285.939484)
		(end 121.148094 -286.475424)
		(width 0.254)
		(layer "F.Cu")
		(net "GND")
	)
	(segment
		(start 413.192214 -258.516628)
		(end 414.297114 -258.516628)
		(width 0.381)
		(layer "F.Cu")
		(net "GND")
	)
	(segment
		(start 301.343314 -248.31675)
		(end 302.448214 -248.31675)
		(width 0.381)
		(layer "F.Cu")
		(net "GND")
	)
	(segment
		(start 345.15171 -40.348916)
		(end 345.554554 -40.946578)
		(width 0.2032)
		(layer "F.Cu")
		(net "GND")
	)
	(segment
		(start 332.796134 -232.250488)
		(end 332.32598 -232.528364)
		(width 0.2032)
		(layer "F.Cu")
		(net "GND")
	)
	(segment
		(start 127.804926 -120.210834)
		(end 127.804926 -120.820434)
		(width 0.3556)
		(layer "F.Cu")
		(net "GND")
	)
	(segment
		(start 272.273014 -236.416596)
		(end 271.168114 -236.416596)
		(width 0.381)
		(layer "F.Cu")
		(net "GND")
	)
	(segment
		(start 48.854614 -271.266666)
		(end 49.959514 -271.266666)
		(width 0.381)
		(layer "F.Cu")
		(net "GND")
	)
	(segment
		(start 200.632314 -211.766658)
		(end 201.737214 -211.766658)
		(width 0.381)
		(layer "F.Cu")
		(net "GND")
	)
	(segment
		(start 456.647804 -383.684272)
		(end 456.647804 -383.271268)
		(width 0.1778)
		(layer "F.Cu")
		(net "GND")
	)
	(segment
		(start 266.619482 -280.61666)
		(end 267.724382 -280.61666)
		(width 0.381)
		(layer "F.Cu")
		(net "GND")
	)
	(segment
		(start 52.298346 -197.316598)
		(end 53.403246 -197.316598)
		(width 0.381)
		(layer "F.Cu")
		(net "GND")
	)
	(segment
		(start 27.328114 -230.466646)
		(end 28.433014 -230.466646)
		(width 0.381)
		(layer "F.Cu")
		(net "GND")
	)
	(segment
		(start 345.593162 -266.405868)
		(end 345.593162 -266.941808)
		(width 0.2032)
		(layer "F.Cu")
		(net "GND")
	)
	(segment
		(start 138.746992 -17.655032)
		(end 138.746992 -16.550132)
		(width 0.3556)
		(layer "F.Cu")
		(net "GND")
	)
	(segment
		(start 350.18218 -226.017582)
		(end 350.182434 -226.017328)
		(width 0.254)
		(layer "F.Cu")
		(net "GND")
	)
	(segment
		(start 409.748482 -196.466714)
		(end 410.853382 -196.466714)
		(width 0.381)
		(layer "F.Cu")
		(net "GND")
	)
	(segment
		(start 130.906266 -227.367084)
		(end 130.906266 -226.831144)
		(width 0.2032)
		(layer "F.Cu")
		(net "GND")
	)
	(segment
		(start 10.873486 -92.287598)
		(end 10.873486 -91.658948)
		(width 0.3556)
		(layer "F.Cu")
		(net "GND")
	)
	(segment
		(start 301.343314 -210.916774)
		(end 302.664114 -210.916774)
		(width 0.381)
		(layer "F.Cu")
		(net "GND")
	)
	(segment
		(start 377.43638 -234.69219)
		(end 377.43638 -234.15625)
		(width 0.2032)
		(layer "F.Cu")
		(net "GND")
	)
	(segment
		(start 386.364734 -248.528078)
		(end 386.905246 -248.528078)
		(width 0.2032)
		(layer "F.Cu")
		(net "GND")
	)
	(segment
		(start 122.447812 -243.644674)
		(end 122.447812 -243.108988)
		(width 0.254)
		(layer "F.Cu")
		(net "GND")
	)
	(segment
		(start 420.736014 -244.916706)
		(end 421.840914 -244.916706)
		(width 0.381)
		(layer "F.Cu")
		(net "GND")
	)
	(segment
		(start 175.4124 -94.738698)
		(end 175.4124 -95.367348)
		(width 0.3556)
		(layer "F.Cu")
		(net "GND")
	)
	(segment
		(start 137.484866 -248.528078)
		(end 137.023602 -248.794524)
		(width 0.254)
		(layer "F.Cu")
		(net "GND")
	)
	(segment
		(start 131.375912 -216.250774)
		(end 131.376166 -216.25052)
		(width 0.254)
		(layer "F.Cu")
		(net "GND")
	)
	(segment
		(start 377.076716 -266.127992)
		(end 377.076462 -266.128246)
		(width 0.254)
		(layer "F.Cu")
		(net "GND")
	)
	(segment
		(start 325.967598 -344.801698)
		(end 326.246744 -344.801698)
		(width 0.1778)
		(layer "F.Cu")
		(net "GND")
	)
	(segment
		(start 39.420546 -265.316716)
		(end 38.315646 -265.316716)
		(width 0.381)
		(layer "F.Cu")
		(net "GND")
	)
	(segment
		(start 267.724382 -286.56661)
		(end 268.829282 -286.56661)
		(width 0.381)
		(layer "F.Cu")
		(net "GND")
	)
	(segment
		(start 425.940982 -312.91657)
		(end 424.836082 -312.91657)
		(width 0.381)
		(layer "F.Cu")
		(net "GND")
	)
	(segment
		(start 272.273014 -223.666558)
		(end 271.168114 -223.666558)
		(width 0.381)
		(layer "F.Cu")
		(net "GND")
	)
	(segment
		(start 382.135634 -242.830858)
		(end 382.135634 -242.294918)
		(width 0.2032)
		(layer "F.Cu")
		(net "GND")
	)
	(segment
		(start 335.138268 -52.679346)
		(end 334.05064 -52.679346)
		(width 0.2032)
		(layer "F.Cu")
		(net "GND")
	)
	(segment
		(start 383.185162 -264.778236)
		(end 383.185416 -265.314176)
		(width 0.2032)
		(layer "F.Cu")
		(net "GND")
	)
	(segment
		(start 138.424666 -235.506006)
		(end 137.954766 -235.783882)
		(width 0.254)
		(layer "F.Cu")
		(net "GND")
	)
	(segment
		(start 15.684246 -216.016586)
		(end 16.789146 -216.016586)
		(width 0.381)
		(layer "F.Cu")
		(net "GND")
	)
	(segment
		(start 208.176114 -219.41663)
		(end 209.281014 -219.41663)
		(width 0.381)
		(layer "F.Cu")
		(net "GND")
	)
	(segment
		(start 428.279814 -263.616694)
		(end 429.384714 -263.616694)
		(width 0.381)
		(layer "F.Cu")
		(net "GND")
	)
	(segment
		(start 157.708346 -212.616796)
		(end 158.813246 -212.616796)
		(width 0.381)
		(layer "F.Cu")
		(net "GND")
	)
	(segment
		(start 12.240514 -213.46668)
		(end 13.345414 -213.46668)
		(width 0.381)
		(layer "F.Cu")
		(net "GND")
	)
	(segment
		(start 23.228046 -214.316564)
		(end 24.332946 -214.316564)
		(width 0.381)
		(layer "F.Cu")
		(net "GND")
	)
	(segment
		(start 114.569494 -276.172676)
		(end 114.569494 -276.708362)
		(width 0.254)
		(layer "F.Cu")
		(net "GND")
	)
	(segment
		(start 27.328114 -233.86669)
		(end 28.433014 -233.86669)
		(width 0.381)
		(layer "F.Cu")
		(net "GND")
	)
	(segment
		(start 338.434934 -250.155964)
		(end 338.434934 -249.620024)
		(width 0.2032)
		(layer "F.Cu")
		(net "GND")
	)
	(segment
		(start 34.871914 -230.466646)
		(end 35.976814 -230.466646)
		(width 0.381)
		(layer "F.Cu")
		(net "GND")
	)
	(segment
		(start 60.947046 -285.716726)
		(end 62.267846 -285.716726)
		(width 0.381)
		(layer "F.Cu")
		(net "GND")
	)
	(segment
		(start 449.677282 -238.116618)
		(end 448.572382 -238.116618)
		(width 0.381)
		(layer "F.Cu")
		(net "GND")
	)
	(segment
		(start 357.148892 -390.43737)
		(end 356.51186 -390.43737)
		(width 0.3556)
		(layer "F.Cu")
		(net "GND")
	)
	(segment
		(start 418.397182 -288.266632)
		(end 417.292282 -288.266632)
		(width 0.381)
		(layer "F.Cu")
		(net "GND")
	)
	(segment
		(start 162.913314 -249.166634)
		(end 161.808414 -249.166634)
		(width 0.381)
		(layer "F.Cu")
		(net "GND")
	)
	(segment
		(start 157.708346 -301.866808)
		(end 158.813246 -301.866808)
		(width 0.381)
		(layer "F.Cu")
		(net "GND")
	)
	(segment
		(start 336.085434 -234.69219)
		(end 336.085434 -234.15625)
		(width 0.254)
		(layer "F.Cu")
		(net "GND")
	)
	(segment
		(start 132.895848 -280.242264)
		(end 132.895594 -280.242518)
		(width 0.254)
		(layer "F.Cu")
		(net "GND")
	)
	(segment
		(start 272.273014 -261.916672)
		(end 271.168114 -261.916672)
		(width 0.381)
		(layer "F.Cu")
		(net "GND")
	)
	(segment
		(start 312.987182 -202.416664)
		(end 314.092082 -202.416664)
		(width 0.381)
		(layer "F.Cu")
		(net "GND")
	)
	(segment
		(start 26.223214 -215.166702)
		(end 27.328114 -215.166702)
		(width 0.381)
		(layer "F.Cu")
		(net "GND")
	)
	(segment
		(start 161.808414 -295.916604)
		(end 162.913314 -295.916604)
		(width 0.381)
		(layer "F.Cu")
		(net "GND")
	)
	(segment
		(start 364.389162 -279.428194)
		(end 364.389162 -279.96388)
		(width 0.254)
		(layer "F.Cu")
		(net "GND")
	)
	(segment
		(start 34.871914 -269.566644)
		(end 33.767014 -269.566644)
		(width 0.381)
		(layer "F.Cu")
		(net "GND")
	)
	(segment
		(start 94.723712 -226.017582)
		(end 94.723966 -226.017328)
		(width 0.254)
		(layer "F.Cu")
		(net "GND")
	)
	(segment
		(start 435.823614 -290.816792)
		(end 436.928514 -290.816792)
		(width 0.381)
		(layer "F.Cu")
		(net "GND")
	)
	(segment
		(start 261.285482 -310.366664)
		(end 260.180582 -310.366664)
		(width 0.381)
		(layer "F.Cu")
		(net "GND")
	)
	(segment
		(start 113.269776 -97.337372)
		(end 113.269776 -98.425762)
		(width 0.3556)
		(layer "F.Cu")
		(net "GND")
	)
	(segment
		(start 414.297114 -313.766708)
		(end 415.639504 -313.766708)
		(width 0.381)
		(layer "F.Cu")
		(net "GND")
	)
	(segment
		(start 260.180582 -204.116686)
		(end 259.075682 -204.116686)
		(width 0.381)
		(layer "F.Cu")
		(net "GND")
	)
	(segment
		(start 136.545066 -225.739198)
		(end 136.545066 -225.203258)
		(width 0.254)
		(layer "F.Cu")
		(net "GND")
	)
	(segment
		(start 158.813246 -278.066754)
		(end 159.918146 -278.066754)
		(width 0.381)
		(layer "F.Cu")
		(net "GND")
	)
	(segment
		(start 70.41896 -63.162688)
		(end 70.41896 -61.558678)
		(width 0.3556)
		(layer "F.Cu")
		(net "GND")
	)
	(segment
		(start 193.088514 -238.116618)
		(end 191.983614 -238.116618)
		(width 0.381)
		(layer "F.Cu")
		(net "GND")
	)
	(segment
		(start 261.285482 -198.166736)
		(end 260.180582 -198.166736)
		(width 0.381)
		(layer "F.Cu")
		(net "GND")
	)
	(segment
		(start 88.255094 -253.383796)
		(end 88.255094 -253.919736)
		(width 0.2032)
		(layer "F.Cu")
		(net "GND")
	)
	(segment
		(start 113.629694 -260.430772)
		(end 113.629948 -260.431026)
		(width 0.254)
		(layer "F.Cu")
		(net "GND")
	)
	(segment
		(start 39.420546 -250.016772)
		(end 38.315646 -250.016772)
		(width 0.381)
		(layer "F.Cu")
		(net "GND")
	)
	(segment
		(start 11.135614 -222.816674)
		(end 12.240514 -222.816674)
		(width 0.381)
		(layer "F.Cu")
		(net "GND")
	)
	(segment
		(start 29.666946 -223.666558)
		(end 30.771846 -223.666558)
		(width 0.381)
		(layer "F.Cu")
		(net "GND")
	)
	(segment
		(start 132.425694 -289.195002)
		(end 132.425694 -289.807142)
		(width 0.2032)
		(layer "F.Cu")
		(net "GND")
	)
	(segment
		(start 53.403246 -227.066602)
		(end 54.508146 -227.066602)
		(width 0.381)
		(layer "F.Cu")
		(net "GND")
	)
	(segment
		(start 312.987182 -284.866588)
		(end 314.307982 -284.866588)
		(width 0.381)
		(layer "F.Cu")
		(net "GND")
	)
	(segment
		(start 266.619482 -232.166668)
		(end 267.724382 -232.166668)
		(width 0.381)
		(layer "F.Cu")
		(net "GND")
	)
	(segment
		(start 307.782214 -306.116736)
		(end 308.887114 -306.116736)
		(width 0.381)
		(layer "F.Cu")
		(net "GND")
	)
	(segment
		(start 425.71416 -144.075658)
		(end 425.71416 -144.685258)
		(width 0.3556)
		(layer "F.Cu")
		(net "GND")
	)
	(segment
		(start 338.93506 -56.438546)
		(end 338.395818 -56.438546)
		(width 0.2032)
		(layer "F.Cu")
		(net "GND")
	)
	(segment
		(start 14.579346 -292.516814)
		(end 15.684246 -292.516814)
		(width 0.381)
		(layer "F.Cu")
		(net "GND")
	)
	(segment
		(start 425.940982 -306.96662)
		(end 424.836082 -306.96662)
		(width 0.381)
		(layer "F.Cu")
		(net "GND")
	)
	(segment
		(start 307.782214 -268.71676)
		(end 308.887114 -268.71676)
		(width 0.381)
		(layer "F.Cu")
		(net "GND")
	)
	(segment
		(start 39.420546 -290.816792)
		(end 38.315646 -290.816792)
		(width 0.381)
		(layer "F.Cu")
		(net "GND")
	)
	(segment
		(start 338.544662 -283.498036)
		(end 338.544662 -284.033722)
		(width 0.254)
		(layer "F.Cu")
		(net "GND")
	)
	(segment
		(start 447.16192 -7.20471)
		(end 447.16065 -7.20344)
		(width 0.3556)
		(layer "F.Cu")
		(net "GND")
	)
	(segment
		(start 211.619846 -268.71676)
		(end 212.724746 -268.71676)
		(width 0.381)
		(layer "F.Cu")
		(net "GND")
	)
	(segment
		(start 339.748876 -52.620418)
		(end 339.748876 -53.149246)
		(width 0.2032)
		(layer "F.Cu")
		(net "GND")
	)
	(segment
		(start 56.182514 -221.116652)
		(end 57.503314 -221.116652)
		(width 0.381)
		(layer "F.Cu")
		(net "GND")
	)
	(segment
		(start 365.479584 -392.688064)
		(end 365.928402 -392.688064)
		(width 0.3556)
		(layer "F.Cu")
		(net "GND")
	)
	(segment
		(start 124.327412 -237.133638)
		(end 124.327412 -236.597952)
		(width 0.254)
		(layer "F.Cu")
		(net "GND")
	)
	(segment
		(start 100.27412 -39.581582)
		(end 99.27082 -39.581582)
		(width 0.3556)
		(layer "F.Cu")
		(net "GND")
	)
	(segment
		(start 449.677282 -245.76659)
		(end 448.572382 -245.76659)
		(width 0.381)
		(layer "F.Cu")
		(net "GND")
	)
	(segment
		(start 343.13368 -250.15571)
		(end 343.13368 -249.620024)
		(width 0.2032)
		(layer "F.Cu")
		(net "GND")
	)
	(segment
		(start 342.303862 -265.592306)
		(end 342.303862 -266.128246)
		(width 0.254)
		(layer "F.Cu")
		(net "GND")
	)
	(segment
		(start 333.507842 -50.799746)
		(end 333.23657 -50.329846)
		(width 0.2032)
		(layer "F.Cu")
		(net "GND")
	)
	(segment
		(start 43.520614 -278.916638)
		(end 42.415714 -278.916638)
		(width 0.381)
		(layer "F.Cu")
		(net "GND")
	)
	(segment
		(start 373.67718 -231.436418)
		(end 373.677434 -231.436164)
		(width 0.2032)
		(layer "F.Cu")
		(net "GND")
	)
	(segment
		(start 366.159034 -220.041724)
		(end 366.159034 -219.506038)
		(width 0.254)
		(layer "F.Cu")
		(net "GND")
	)
	(segment
		(start 429.129952 -385.521962)
		(end 429.764952 -385.521962)
		(width 0.3556)
		(layer "F.Cu")
		(net "GND")
	)
	(segment
		(start 432.379882 -239.81664)
		(end 433.484782 -239.81664)
		(width 0.381)
		(layer "F.Cu")
		(net "GND")
	)
	(segment
		(start 49.917604 -145.008854)
		(end 49.917604 -144.22755)
		(width 0.381)
		(layer "F.Cu")
		(net "GND")
	)
	(segment
		(start 361.569762 -285.939484)
		(end 361.569762 -286.475424)
		(width 0.254)
		(layer "F.Cu")
		(net "GND")
	)
	(segment
		(start 204.076046 -311.216802)
		(end 205.180946 -311.216802)
		(width 0.381)
		(layer "F.Cu")
		(net "GND")
	)
	(segment
		(start 346.532962 -281.05608)
		(end 346.532962 -281.591766)
		(width 0.254)
		(layer "F.Cu")
		(net "GND")
	)
	(segment
		(start 26.223214 -239.81664)
		(end 27.328114 -239.81664)
		(width 0.381)
		(layer "F.Cu")
		(net "GND")
	)
	(segment
		(start 90.494866 -240.389156)
		(end 90.494866 -239.853216)
		(width 0.2032)
		(layer "F.Cu")
		(net "GND")
	)
	(segment
		(start 65.047114 -238.116618)
		(end 66.367914 -238.116618)
		(width 0.381)
		(layer "F.Cu")
		(net "GND")
	)
	(segment
		(start 104.701848 -278.614378)
		(end 104.701848 -279.150064)
		(width 0.2032)
		(layer "F.Cu")
		(net "GND")
	)
	(segment
		(start 84.856066 -238.761524)
		(end 84.386166 -239.0394)
		(width 0.254)
		(layer "F.Cu")
		(net "GND")
	)
	(segment
		(start 127.616712 -223.297496)
		(end 127.616712 -222.76181)
		(width 0.254)
		(layer "F.Cu")
		(net "GND")
	)
	(segment
		(start 382.135634 -248.806208)
		(end 382.135634 -249.342148)
		(width 0.2032)
		(layer "F.Cu")
		(net "GND")
	)
	(segment
		(start 43.520614 -308.666642)
		(end 42.415714 -308.666642)
		(width 0.381)
		(layer "F.Cu")
		(net "GND")
	)
	(segment
		(start 69.179694 -30.541722)
		(end 69.172582 -30.53461)
		(width 0.17272)
		(layer "F.Cu")
		(net "GND")
	)
	(segment
		(start 30.771846 -289.11677)
		(end 31.876746 -289.11677)
		(width 0.381)
		(layer "F.Cu")
		(net "GND")
	)
	(segment
		(start 97.183448 -286.7533)
		(end 97.183448 -287.288986)
		(width 0.254)
		(layer "F.Cu")
		(net "GND")
	)
	(segment
		(start 378.84608 -232.250234)
		(end 378.84608 -231.714548)
		(width 0.2032)
		(layer "F.Cu")
		(net "GND")
	)
	(segment
		(start 439.923682 -249.166634)
		(end 441.028582 -249.166634)
		(width 0.381)
		(layer "F.Cu")
		(net "GND")
	)
	(segment
		(start 153.256996 -17.655032)
		(end 153.256996 -16.550132)
		(width 0.3556)
		(layer "F.Cu")
		(net "GND")
	)
	(segment
		(start 364.279434 -220.041724)
		(end 364.279434 -219.506038)
		(width 0.254)
		(layer "F.Cu")
		(net "GND")
	)
	(segment
		(start 394.899896 -53.824886)
		(end 394.899896 -57.030112)
		(width 0.3556)
		(layer "F.Cu")
		(net "GND")
	)
	(segment
		(start 375.197116 -284.033468)
		(end 375.196862 -284.033722)
		(width 0.254)
		(layer "F.Cu")
		(net "GND")
	)
	(segment
		(start 335.899252 -57.605168)
		(end 336.899758 -57.605168)
		(width 0.2032)
		(layer "F.Cu")
		(net "GND")
	)
	(segment
		(start 94.833948 -266.406122)
		(end 94.833948 -266.941808)
		(width 0.2032)
		(layer "F.Cu")
		(net "GND")
	)
	(segment
		(start 424.836082 -198.166736)
		(end 425.940982 -198.166736)
		(width 0.381)
		(layer "F.Cu")
		(net "GND")
	)
	(segment
		(start 165.252146 -231.316784)
		(end 166.357046 -231.316784)
		(width 0.381)
		(layer "F.Cu")
		(net "GND")
	)
	(segment
		(start 91.434666 -237.133892)
		(end 91.434412 -237.133638)
		(width 0.2032)
		(layer "F.Cu")
		(net "GND")
	)
	(segment
		(start 169.137584 -235.566712)
		(end 170.457114 -235.566712)
		(width 0.381)
		(layer "F.Cu")
		(net "GND")
	)
	(segment
		(start 289.250882 -194.766692)
		(end 290.355782 -194.766692)
		(width 0.381)
		(layer "F.Cu")
		(net "GND")
	)
	(segment
		(start 294.904414 -313.766708)
		(end 293.799514 -313.766708)
		(width 0.381)
		(layer "F.Cu")
		(net "GND")
	)
	(segment
		(start 158.813246 -206.666592)
		(end 157.499304 -206.666592)
		(width 0.381)
		(layer "F.Cu")
		(net "GND")
	)
	(segment
		(start 7.035546 -201.56678)
		(end 8.140446 -201.56678)
		(width 0.381)
		(layer "F.Cu")
		(net "GND")
	)
	(segment
		(start 39.420546 -270.416782)
		(end 38.315646 -270.416782)
		(width 0.381)
		(layer "F.Cu")
		(net "GND")
	)
	(segment
		(start 449.677282 -211.766658)
		(end 448.572382 -211.766658)
		(width 0.381)
		(layer "F.Cu")
		(net "GND")
	)
	(segment
		(start 33.767014 -219.41663)
		(end 34.871914 -219.41663)
		(width 0.381)
		(layer "F.Cu")
		(net "GND")
	)
	(segment
		(start 347.472762 -255.011682)
		(end 347.472762 -255.547368)
		(width 0.2032)
		(layer "F.Cu")
		(net "GND")
	)
	(segment
		(start 374.257316 -259.081016)
		(end 374.257316 -259.093462)
		(width 0.2032)
		(layer "F.Cu")
		(net "GND")
	)
	(segment
		(start 311.882282 -245.76659)
		(end 312.987182 -245.76659)
		(width 0.381)
		(layer "F.Cu")
		(net "GND")
	)
	(segment
		(start 98.592894 -274.54479)
		(end 98.592894 -275.08073)
		(width 0.2032)
		(layer "F.Cu")
		(net "GND")
	)
	(segment
		(start 410.853382 -200.716642)
		(end 411.958282 -200.716642)
		(width 0.381)
		(layer "F.Cu")
		(net "GND")
	)
	(segment
		(start 277.607014 -311.216802)
		(end 278.711914 -311.216802)
		(width 0.381)
		(layer "F.Cu")
		(net "GND")
	)
	(segment
		(start 137.484866 -245.27256)
		(end 136.545066 -244.73662)
		(width 0.254)
		(layer "F.Cu")
		(net "GND")
	)
	(segment
		(start 85.325712 -223.297496)
		(end 85.325712 -222.761556)
		(width 0.254)
		(layer "F.Cu")
		(net "GND")
	)
	(segment
		(start 63.942214 -262.76681)
		(end 65.047114 -262.76681)
		(width 0.381)
		(layer "F.Cu")
		(net "GND")
	)
	(segment
		(start 127.616712 -216.78646)
		(end 127.616712 -216.250774)
		(width 0.254)
		(layer "F.Cu")
		(net "GND")
	)
	(segment
		(start 207.071214 -258.516628)
		(end 208.176114 -258.516628)
		(width 0.381)
		(layer "F.Cu")
		(net "GND")
	)
	(segment
		(start 452.016114 -234.716574)
		(end 450.911214 -234.716574)
		(width 0.381)
		(layer "F.Cu")
		(net "GND")
	)
	(segment
		(start 342.19134 -49.859946)
		(end 342.190578 -49.859946)
		(width 0.2032)
		(layer "F.Cu")
		(net "GND")
	)
	(segment
		(start 365.689134 -217.600276)
		(end 365.689134 -217.064336)
		(width 0.254)
		(layer "F.Cu")
		(net "GND")
	)
	(segment
		(start 418.397182 -222.816674)
		(end 417.292282 -222.816674)
		(width 0.381)
		(layer "F.Cu")
		(net "GND")
	)
	(segment
		(start 31.69793 -428.843948)
		(end 32.30753 -428.843948)
		(width 0.3556)
		(layer "F.Cu")
		(net "GND")
	)
	(segment
		(start 49.959514 -198.166736)
		(end 51.064414 -198.166736)
		(width 0.381)
		(layer "F.Cu")
		(net "GND")
	)
	(segment
		(start 136.184894 -281.05608)
		(end 136.184894 -281.59202)
		(width 0.254)
		(layer "F.Cu")
		(net "GND")
	)
	(segment
		(start 262.519414 -214.316564)
		(end 263.624314 -214.316564)
		(width 0.381)
		(layer "F.Cu")
		(net "GND")
	)
	(segment
		(start 301.343314 -231.316784)
		(end 302.448214 -231.316784)
		(width 0.381)
		(layer "F.Cu")
		(net "GND")
	)
	(segment
		(start 421.840914 -283.166566)
		(end 420.736014 -283.166566)
		(width 0.381)
		(layer "F.Cu")
		(net "GND")
	)
	(segment
		(start 267.724382 -204.116686)
		(end 268.829282 -204.116686)
		(width 0.381)
		(layer "F.Cu")
		(net "GND")
	)
	(segment
		(start 363.449362 -272.917158)
		(end 363.449362 -273.453098)
		(width 0.254)
		(layer "F.Cu")
		(net "GND")
	)
	(segment
		(start 180.339746 -263.616694)
		(end 181.444646 -263.616694)
		(width 0.381)
		(layer "F.Cu")
		(net "GND")
	)
	(segment
		(start 374.617234 -220.041724)
		(end 374.617234 -219.506038)
		(width 0.254)
		(layer "F.Cu")
		(net "GND")
	)
	(segment
		(start 43.520614 -215.166702)
		(end 42.415714 -215.166702)
		(width 0.381)
		(layer "F.Cu")
		(net "GND")
	)
	(segment
		(start 346.384626 -56.95442)
		(end 345.96959 -57.454546)
		(width 0.2032)
		(layer "F.Cu")
		(net "GND")
	)
	(segment
		(start 128.666494 -269.66164)
		(end 128.666748 -270.167862)
		(width 0.2032)
		(layer "F.Cu")
		(net "GND")
	)
	(segment
		(start 436.928514 -276.366732)
		(end 438.033414 -276.366732)
		(width 0.381)
		(layer "F.Cu")
		(net "GND")
	)
	(segment
		(start 126.534926 -122.496834)
		(end 126.534926 -123.112784)
		(width 0.3556)
		(layer "F.Cu")
		(net "GND")
	)
	(segment
		(start 443.367414 -285.716726)
		(end 444.472314 -285.716726)
		(width 0.381)
		(layer "F.Cu")
		(net "GND")
	)
	(segment
		(start 428.279814 -216.016586)
		(end 429.384714 -216.016586)
		(width 0.381)
		(layer "F.Cu")
		(net "GND")
	)
	(segment
		(start 22.123146 -300.166786)
		(end 23.228046 -300.166786)
		(width 0.381)
		(layer "F.Cu")
		(net "GND")
	)
	(segment
		(start 65.047114 -284.866588)
		(end 66.367914 -284.866588)
		(width 0.381)
		(layer "F.Cu")
		(net "GND")
	)
	(segment
		(start 308.887114 -306.116736)
		(end 309.992014 -306.116736)
		(width 0.381)
		(layer "F.Cu")
		(net "GND")
	)
	(segment
		(start 127.616712 -239.57534)
		(end 127.616966 -239.575086)
		(width 0.2032)
		(layer "F.Cu")
		(net "GND")
	)
	(segment
		(start 158.813246 -195.616576)
		(end 159.918146 -195.616576)
		(width 0.381)
		(layer "F.Cu")
		(net "GND")
	)
	(segment
		(start 366.268762 -284.847284)
		(end 366.269016 -284.847538)
		(width 0.254)
		(layer "F.Cu")
		(net "GND")
	)
	(segment
		(start 462.555082 -221.116652)
		(end 463.659982 -221.116652)
		(width 0.381)
		(layer "F.Cu")
		(net "GND")
	)
	(segment
		(start 435.823614 -203.266802)
		(end 436.928514 -203.266802)
		(width 0.381)
		(layer "F.Cu")
		(net "GND")
	)
	(segment
		(start 26.223214 -262.76681)
		(end 27.328114 -262.76681)
		(width 0.381)
		(layer "F.Cu")
		(net "GND")
	)
	(segment
		(start 193.088514 -205.816708)
		(end 191.983614 -205.816708)
		(width 0.381)
		(layer "F.Cu")
		(net "GND")
	)
	(segment
		(start 260.180582 -280.61666)
		(end 259.075682 -280.61666)
		(width 0.381)
		(layer "F.Cu")
		(net "GND")
	)
	(segment
		(start 346.42298 -237.947454)
		(end 346.42298 -237.411514)
		(width 0.254)
		(layer "F.Cu")
		(net "GND")
	)
	(segment
		(start 285.150814 -225.36658)
		(end 286.255714 -225.36658)
		(width 0.381)
		(layer "F.Cu")
		(net "GND")
	)
	(segment
		(start 172.795946 -217.716608)
		(end 173.900846 -217.716608)
		(width 0.381)
		(layer "F.Cu")
		(net "GND")
	)
	(segment
		(start 418.397182 -213.46668)
		(end 417.292282 -213.46668)
		(width 0.381)
		(layer "F.Cu")
		(net "GND")
	)
	(segment
		(start 123.857512 -220.041978)
		(end 123.857766 -220.041724)
		(width 0.254)
		(layer "F.Cu")
		(net "GND")
	)
	(segment
		(start 306.49037 -221.116652)
		(end 305.443382 -221.116652)
		(width 0.381)
		(layer "F.Cu")
		(net "GND")
	)
	(segment
		(start 339.014562 -285.939484)
		(end 339.014562 -286.475424)
		(width 0.2032)
		(layer "F.Cu")
		(net "GND")
	)
	(segment
		(start 190.093346 -261.916672)
		(end 188.988446 -261.916672)
		(width 0.381)
		(layer "F.Cu")
		(net "GND")
	)
	(segment
		(start 409.748482 -295.916604)
		(end 410.853382 -295.916604)
		(width 0.381)
		(layer "F.Cu")
		(net "GND")
	)
	(segment
		(start 328.194162 -53.003196)
		(end 328.194162 -53.902102)
		(width 0.2032)
		(layer "F.Cu")
		(net "GND")
	)
	(segment
		(start 177.108104 -55.79999)
		(end 178.289204 -55.79999)
		(width 0.254)
		(layer "F.Cu")
		(net "GND")
	)
	(segment
		(start 84.856066 -243.644928)
		(end 84.856066 -243.108988)
		(width 0.2032)
		(layer "F.Cu")
		(net "GND")
	)
	(segment
		(start 452.016114 -223.666558)
		(end 450.911214 -223.666558)
		(width 0.381)
		(layer "F.Cu")
		(net "GND")
	)
	(segment
		(start 130.906266 -245.27256)
		(end 130.906012 -245.272306)
		(width 0.2032)
		(layer "F.Cu")
		(net "GND")
	)
	(segment
		(start 15.684246 -204.96657)
		(end 16.789146 -204.96657)
		(width 0.381)
		(layer "F.Cu")
		(net "GND")
	)
	(segment
		(start 382.245362 -253.919482)
		(end 382.245616 -253.919736)
		(width 0.2032)
		(layer "F.Cu")
		(net "GND")
	)
	(segment
		(start 384.124962 -287.567116)
		(end 384.16484 -287.606994)
		(width 0.254)
		(layer "F.Cu")
		(net "GND")
	)
	(segment
		(start 130.546094 -289.195002)
		(end 130.546094 -289.807142)
		(width 0.2032)
		(layer "F.Cu")
		(net "GND")
	)
	(segment
		(start 138.534648 -285.125414)
		(end 138.534648 -285.6611)
		(width 0.2032)
		(layer "F.Cu")
		(net "GND")
	)
	(segment
		(start 421.292528 -343.077038)
		(end 421.292528 -344.017346)
		(width 0.508)
		(layer "F.Cu")
		(net "GND")
	)
	(segment
		(start 97.543366 -239.575086)
		(end 97.543366 -239.0394)
		(width 0.2032)
		(layer "F.Cu")
		(net "GND")
	)
	(segment
		(start 407.91765 -295.041574)
		(end 407.892504 -295.06672)
		(width 0.381)
		(layer "F.Cu")
		(net "GND")
	)
	(segment
		(start 161.808414 -207.51673)
		(end 162.913314 -207.51673)
		(width 0.381)
		(layer "F.Cu")
		(net "GND")
	)
	(segment
		(start 128.196848 -284.033468)
		(end 128.196594 -284.033722)
		(width 0.254)
		(layer "F.Cu")
		(net "GND")
	)
	(segment
		(start 456.116182 -216.866724)
		(end 455.011282 -216.866724)
		(width 0.381)
		(layer "F.Cu")
		(net "GND")
	)
	(segment
		(start 289.250882 -306.96662)
		(end 290.355782 -306.96662)
		(width 0.381)
		(layer "F.Cu")
		(net "GND")
	)
	(segment
		(start 104.121966 -229.808532)
		(end 104.121966 -229.272846)
		(width 0.2032)
		(layer "F.Cu")
		(net "GND")
	)
	(segment
		(start 374.61698 -247.714262)
		(end 374.61698 -247.178322)
		(width 0.2032)
		(layer "F.Cu")
		(net "GND")
	)
	(segment
		(start 347.942916 -287.288986)
		(end 347.942662 -287.28924)
		(width 0.254)
		(layer "F.Cu")
		(net "GND")
	)
	(segment
		(start 277.607014 -236.416596)
		(end 278.711914 -236.416596)
		(width 0.381)
		(layer "F.Cu")
		(net "GND")
	)
	(segment
		(start 347.36278 -247.714262)
		(end 347.36278 -247.178576)
		(width 0.2032)
		(layer "F.Cu")
		(net "GND")
	)
	(segment
		(start 135.714994 -265.592306)
		(end 135.714994 -266.128246)
		(width 0.254)
		(layer "F.Cu")
		(net "GND")
	)
	(segment
		(start 425.940982 -301.01667)
		(end 424.836082 -301.01667)
		(width 0.381)
		(layer "F.Cu")
		(net "GND")
	)
	(segment
		(start 372.267734 -250.155964)
		(end 372.26748 -250.15571)
		(width 0.2032)
		(layer "F.Cu")
		(net "GND")
	)
	(segment
		(start 181.444646 -289.11677)
		(end 180.339746 -289.11677)
		(width 0.381)
		(layer "F.Cu")
		(net "GND")
	)
	(segment
		(start 361.45978 -244.458744)
		(end 361.45978 -243.923058)
		(width 0.254)
		(layer "F.Cu")
		(net "GND")
	)
	(segment
		(start 207.071214 -286.56661)
		(end 208.176114 -286.56661)
		(width 0.381)
		(layer "F.Cu")
		(net "GND")
	)
	(segment
		(start 363.046518 -362.618528)
		(end 363.656118 -362.618528)
		(width 0.381)
		(layer "F.Cu")
		(net "GND")
	)
	(segment
		(start 115.979448 -279.150064)
		(end 115.979194 -279.150318)
		(width 0.254)
		(layer "F.Cu")
		(net "GND")
	)
	(segment
		(start 111.690912 -399.409666)
		(end 112.300512 -400.019266)
		(width 0.3556)
		(layer "F.Cu")
		(net "GND")
	)
	(segment
		(start 337.02498 -223.297496)
		(end 337.02498 -222.76181)
		(width 0.254)
		(layer "F.Cu")
		(net "GND")
	)
	(segment
		(start 118.043452 -338.60359)
		(end 117.76837 -338.328508)
		(width 0.381)
		(layer "F.Cu")
		(net "GND")
	)
	(segment
		(start 423.096436 -367.208308)
		(end 423.096436 -367.06937)
		(width 0.381)
		(layer "F.Cu")
		(net "GND")
	)
	(segment
		(start 281.707082 -235.566712)
		(end 282.811982 -235.566712)
		(width 0.381)
		(layer "F.Cu")
		(net "GND")
	)
	(segment
		(start 131.016248 -259.093462)
		(end 131.015994 -259.616956)
		(width 0.2032)
		(layer "F.Cu")
		(net "GND")
	)
	(segment
		(start 89.194894 -277.800562)
		(end 88.72474 -277.522686)
		(width 0.254)
		(layer "F.Cu")
		(net "GND")
	)
	(segment
		(start 211.619846 -197.316598)
		(end 212.724746 -197.316598)
		(width 0.381)
		(layer "F.Cu")
		(net "GND")
	)
	(segment
		(start 99.422712 -226.017582)
		(end 99.422966 -226.017328)
		(width 0.254)
		(layer "F.Cu")
		(net "GND")
	)
	(segment
		(start 272.273014 -244.916706)
		(end 271.168114 -244.916706)
		(width 0.381)
		(layer "F.Cu")
		(net "GND")
	)
	(segment
		(start 100.002848 -287.288986)
		(end 100.002594 -287.28924)
		(width 0.254)
		(layer "F.Cu")
		(net "GND")
	)
	(segment
		(start 307.782214 -231.316784)
		(end 308.887114 -231.316784)
		(width 0.381)
		(layer "F.Cu")
		(net "GND")
	)
	(segment
		(start 215.719914 -233.86669)
		(end 216.824814 -233.86669)
		(width 0.381)
		(layer "F.Cu")
		(net "GND")
	)
	(segment
		(start 382.135634 -216.78646)
		(end 382.135634 -216.25052)
		(width 0.254)
		(layer "F.Cu")
		(net "GND")
	)
	(segment
		(start 352.06178 -233.064304)
		(end 352.062034 -233.06405)
		(width 0.2032)
		(layer "F.Cu")
		(net "GND")
	)
	(segment
		(start 211.619846 -251.716794)
		(end 212.724746 -251.716794)
		(width 0.381)
		(layer "F.Cu")
		(net "GND")
	)
	(segment
		(start 97.543112 -246.08663)
		(end 97.543112 -245.55069)
		(width 0.2032)
		(layer "F.Cu")
		(net "GND")
	)
	(segment
		(start 384.124962 -253.383796)
		(end 384.124962 -253.919736)
		(width 0.2032)
		(layer "F.Cu")
		(net "GND")
	)
	(segment
		(start 254.975614 -273.816572)
		(end 256.080514 -273.816572)
		(width 0.381)
		(layer "F.Cu")
		(net "GND")
	)
	(segment
		(start 162.913314 -196.466714)
		(end 161.808414 -196.466714)
		(width 0.381)
		(layer "F.Cu")
		(net "GND")
	)
	(segment
		(start 180.555646 -113.77549)
		(end 180.955696 -114.17554)
		(width 0.3556)
		(layer "F.Cu")
		(net "GND")
	)
	(segment
		(start 375.667016 -270.167862)
		(end 375.667016 -270.19758)
		(width 0.2032)
		(layer "F.Cu")
		(net "GND")
	)
	(segment
		(start 384.595116 -282.405582)
		(end 384.594862 -282.405836)
		(width 0.254)
		(layer "F.Cu")
		(net "GND")
	)
	(segment
		(start 208.176114 -238.116618)
		(end 209.281014 -238.116618)
		(width 0.381)
		(layer "F.Cu")
		(net "GND")
	)
	(segment
		(start 351.231962 -272.917158)
		(end 351.231962 -273.453098)
		(width 0.2032)
		(layer "F.Cu")
		(net "GND")
	)
	(segment
		(start 444.472314 -309.51678)
		(end 445.577214 -309.51678)
		(width 0.381)
		(layer "F.Cu")
		(net "GND")
	)
	(segment
		(start 370.388134 -246.900446)
		(end 370.388134 -246.364506)
		(width 0.2032)
		(layer "F.Cu")
		(net "GND")
	)
	(segment
		(start 45.859446 -210.916774)
		(end 46.964346 -210.916774)
		(width 0.381)
		(layer "F.Cu")
		(net "GND")
	)
	(segment
		(start 256.080514 -208.366614)
		(end 257.185414 -208.366614)
		(width 0.381)
		(layer "F.Cu")
		(net "GND")
	)
	(segment
		(start 336.399632 -38.880288)
		(end 335.899252 -39.295324)
		(width 0.2032)
		(layer "F.Cu")
		(net "GND")
	)
	(segment
		(start 342.773762 -272.917158)
		(end 342.773762 -273.453098)
		(width 0.2032)
		(layer "F.Cu")
		(net "GND")
	)
	(segment
		(start 308.887114 -206.666592)
		(end 310.207914 -206.666592)
		(width 0.381)
		(layer "F.Cu")
		(net "GND")
	)
	(segment
		(start 194.193414 -194.766692)
		(end 193.088514 -194.766692)
		(width 0.381)
		(layer "F.Cu")
		(net "GND")
	)
	(segment
		(start 49.959514 -216.866724)
		(end 48.854614 -216.866724)
		(width 0.381)
		(layer "F.Cu")
		(net "GND")
	)
	(segment
		(start 380.835916 -286.7533)
		(end 380.835916 -287.288986)
		(width 0.254)
		(layer "F.Cu")
		(net "GND")
	)
	(segment
		(start 428.279814 -311.216802)
		(end 429.384714 -311.216802)
		(width 0.381)
		(layer "F.Cu")
		(net "GND")
	)
	(segment
		(start 462.555082 -245.76659)
		(end 463.659982 -245.76659)
		(width 0.381)
		(layer "F.Cu")
		(net "GND")
	)
	(segment
		(start 346.799662 -47.44974)
		(end 345.96959 -47.44974)
		(width 0.2032)
		(layer "F.Cu")
		(net "GND")
	)
	(segment
		(start 133.255512 -223.297496)
		(end 133.255512 -222.76181)
		(width 0.254)
		(layer "F.Cu")
		(net "GND")
	)
	(segment
		(start 263.624314 -311.216802)
		(end 264.729214 -311.216802)
		(width 0.381)
		(layer "F.Cu")
		(net "GND")
	)
	(segment
		(start 118.312438 -336.27314)
		(end 117.99316 -336.592418)
		(width 0.254)
		(layer "F.Cu")
		(net "GND")
	)
	(segment
		(start 342.194134 -233.87812)
		(end 342.19388 -233.877866)
		(width 0.2032)
		(layer "F.Cu")
		(net "GND")
	)
	(segment
		(start 45.859446 -300.166786)
		(end 46.964346 -300.166786)
		(width 0.381)
		(layer "F.Cu")
		(net "GND")
	)
	(segment
		(start 135.135112 -223.297496)
		(end 135.135112 -222.76181)
		(width 0.254)
		(layer "F.Cu")
		(net "GND")
	)
	(segment
		(start 457.221082 -258.516628)
		(end 456.116182 -258.516628)
		(width 0.381)
		(layer "F.Cu")
		(net "GND")
	)
	(segment
		(start 367.208562 -276.172676)
		(end 367.208562 -276.708616)
		(width 0.2032)
		(layer "F.Cu")
		(net "GND")
	)
	(segment
		(start 188.988446 -210.916774)
		(end 187.883546 -210.916774)
		(width 0.381)
		(layer "F.Cu")
		(net "GND")
	)
	(segment
		(start 202.971146 -201.56678)
		(end 204.076046 -201.56678)
		(width 0.381)
		(layer "F.Cu")
		(net "GND")
	)
	(segment
		(start 346.384626 -56.95442)
		(end 345.554554 -56.95442)
		(width 0.2032)
		(layer "F.Cu")
		(net "GND")
	)
	(segment
		(start 113.519712 -241.203226)
		(end 113.519712 -240.668048)
		(width 0.254)
		(layer "F.Cu")
		(net "GND")
	)
	(segment
		(start 289.250882 -216.866724)
		(end 290.355782 -216.866724)
		(width 0.381)
		(layer "F.Cu")
		(net "GND")
	)
	(segment
		(start 429.384714 -283.166566)
		(end 430.489614 -283.166566)
		(width 0.381)
		(layer "F.Cu")
		(net "GND")
	)
	(segment
		(start 272.273014 -197.316598)
		(end 271.168114 -197.316598)
		(width 0.381)
		(layer "F.Cu")
		(net "GND")
	)
	(segment
		(start 126.153672 -340.002622)
		(end 126.065026 -340.002622)
		(width 0.254)
		(layer "F.Cu")
		(net "GND")
	)
	(segment
		(start 415.978594 -45.83684)
		(end 417.03752 -45.83684)
		(width 0.3556)
		(layer "F.Cu")
		(net "GND")
	)
	(segment
		(start 428.279814 -287.416748)
		(end 429.384714 -287.416748)
		(width 0.381)
		(layer "F.Cu")
		(net "GND")
	)
	(segment
		(start 124.327666 -232.250488)
		(end 124.327412 -232.250234)
		(width 0.254)
		(layer "F.Cu")
		(net "GND")
	)
	(segment
		(start 458.455014 -279.766776)
		(end 459.559914 -279.766776)
		(width 0.381)
		(layer "F.Cu")
		(net "GND")
	)
	(segment
		(start 212.724746 -298.466764)
		(end 211.619846 -298.466764)
		(width 0.381)
		(layer "F.Cu")
		(net "GND")
	)
	(segment
		(start 335.67878 -43.281346)
		(end 335.138268 -43.281346)
		(width 0.2032)
		(layer "F.Cu")
		(net "GND")
	)
	(segment
		(start 53.403246 -250.016772)
		(end 54.508146 -250.016772)
		(width 0.381)
		(layer "F.Cu")
		(net "GND")
	)
	(segment
		(start 350.698054 -334.191102)
		(end 350.376998 -334.191102)
		(width 0.2032)
		(layer "F.Cu")
		(net "GND")
	)
	(segment
		(start 87.205312 -222.76181)
		(end 87.205566 -222.761556)
		(width 0.2032)
		(layer "F.Cu")
		(net "GND")
	)
	(segment
		(start 312.987182 -267.866622)
		(end 314.092082 -267.866622)
		(width 0.381)
		(layer "F.Cu")
		(net "GND")
	)
	(segment
		(start 263.624314 -290.816792)
		(end 264.729214 -290.816792)
		(width 0.381)
		(layer "F.Cu")
		(net "GND")
	)
	(segment
		(start 90.604594 -283.498036)
		(end 90.604594 -284.033722)
		(width 0.254)
		(layer "F.Cu")
		(net "GND")
	)
	(segment
		(start 144.564608 -105.174796)
		(end 144.54632 -105.156508)
		(width 0.3556)
		(layer "F.Cu")
		(net "GND")
	)
	(segment
		(start 92.844366 -237.947454)
		(end 92.844366 -237.411514)
		(width 0.254)
		(layer "F.Cu")
		(net "GND")
	)
	(segment
		(start 133.255512 -222.76181)
		(end 133.255766 -222.761556)
		(width 0.254)
		(layer "F.Cu")
		(net "GND")
	)
	(segment
		(start 425.940982 -204.116686)
		(end 427.045882 -204.116686)
		(width 0.381)
		(layer "F.Cu")
		(net "GND")
	)
	(segment
		(start 364.859316 -276.986492)
		(end 364.859062 -277.522432)
		(width 0.2032)
		(layer "F.Cu")
		(net "GND")
	)
	(segment
		(start 94.254066 -232.250488)
		(end 94.254066 -231.714548)
		(width 0.2032)
		(layer "F.Cu")
		(net "GND")
	)
	(segment
		(start 56.867044 -11.26998)
		(end 56.867044 -10.16508)
		(width 0.3556)
		(layer "F.Cu")
		(net "GND")
	)
	(segment
		(start 311.882282 -264.466578)
		(end 312.987182 -264.466578)
		(width 0.381)
		(layer "F.Cu")
		(net "GND")
	)
	(segment
		(start 115.10391 -363.80293)
		(end 115.4303 -364.12932)
		(width 0.4572)
		(layer "F.Cu")
		(net "GND")
	)
	(segment
		(start 340.894162 -265.313922)
		(end 340.894416 -265.314176)
		(width 0.2032)
		(layer "F.Cu")
		(net "GND")
	)
	(segment
		(start 380.365762 -276.172676)
		(end 380.365762 -276.708616)
		(width 0.2032)
		(layer "F.Cu")
		(net "GND")
	)
	(segment
		(start 29.666946 -240.666778)
		(end 30.771846 -240.666778)
		(width 0.381)
		(layer "F.Cu")
		(net "GND")
	)
	(segment
		(start 406.753314 -263.616694)
		(end 407.858214 -263.616694)
		(width 0.381)
		(layer "F.Cu")
		(net "GND")
	)
	(segment
		(start 336.899758 -57.605168)
		(end 337.900264 -57.605168)
		(width 0.254)
		(layer "F.Cu")
		(net "GND")
	)
	(segment
		(start 211.059522 -134.18312)
		(end 211.591906 -134.18312)
		(width 0.254)
		(layer "F.Cu")
		(net "GND")
	)
	(segment
		(start 214.615014 -194.766692)
		(end 215.719914 -194.766692)
		(width 0.381)
		(layer "F.Cu")
		(net "GND")
	)
	(segment
		(start 172.795946 -246.616728)
		(end 173.900846 -246.616728)
		(width 0.381)
		(layer "F.Cu")
		(net "GND")
	)
	(segment
		(start 333.23657 -40.931846)
		(end 332.697328 -40.931846)
		(width 0.2032)
		(layer "F.Cu")
		(net "GND")
	)
	(segment
		(start 340.894162 -269.66164)
		(end 340.894416 -269.661894)
		(width 0.2032)
		(layer "F.Cu")
		(net "GND")
	)
	(segment
		(start 31.147004 -10.16508)
		(end 31.147004 -11.26998)
		(width 0.3556)
		(layer "F.Cu")
		(net "GND")
	)
	(segment
		(start 285.150814 -227.066602)
		(end 286.255714 -227.066602)
		(width 0.381)
		(layer "F.Cu")
		(net "GND")
	)
	(segment
		(start 369.088162 -276.172676)
		(end 369.088416 -276.708616)
		(width 0.2032)
		(layer "F.Cu")
		(net "GND")
	)
	(segment
		(start 53.403246 -272.116804)
		(end 54.508146 -272.116804)
		(width 0.381)
		(layer "F.Cu")
		(net "GND")
	)
	(segment
		(start 33.767014 -198.166736)
		(end 34.871914 -198.166736)
		(width 0.381)
		(layer "F.Cu")
		(net "GND")
	)
	(segment
		(start 45.859446 -197.316598)
		(end 46.964346 -197.316598)
		(width 0.381)
		(layer "F.Cu")
		(net "GND")
	)
	(segment
		(start 412.956756 -8.320024)
		(end 412.956756 -7.215124)
		(width 0.3556)
		(layer "F.Cu")
		(net "GND")
	)
	(segment
		(start 295.747186 -363.25048)
		(end 295.352724 -362.856018)
		(width 0.2032)
		(layer "F.Cu")
		(net "GND")
	)
	(segment
		(start 14.579346 -242.3668)
		(end 15.684246 -242.3668)
		(width 0.381)
		(layer "F.Cu")
		(net "GND")
	)
	(segment
		(start 118.300246 -355.914452)
		(end 118.737126 -355.914452)
		(width 0.381)
		(layer "F.Cu")
		(net "GND")
	)
	(segment
		(start 136.19988 -271.834102)
		(end 136.196578 -271.834356)
		(width 0.254)
		(layer "F.Cu")
		(net "GND")
	)
	(segment
		(start 56.398414 -228.766624)
		(end 57.503314 -228.766624)
		(width 0.381)
		(layer "F.Cu")
		(net "GND")
	)
	(segment
		(start 173.900846 -248.31675)
		(end 175.005746 -248.31675)
		(width 0.381)
		(layer "F.Cu")
		(net "GND")
	)
	(segment
		(start 209.34553 -131.846828)
		(end 208.71688 -131.846828)
		(width 0.3556)
		(layer "F.Cu")
		(net "GND")
	)
	(segment
		(start 166.357046 -298.466764)
		(end 165.252146 -298.466764)
		(width 0.381)
		(layer "F.Cu")
		(net "GND")
	)
	(segment
		(start 453.121014 -287.416748)
		(end 452.016114 -287.416748)
		(width 0.381)
		(layer "F.Cu")
		(net "GND")
	)
	(segment
		(start 178.000914 -275.516594)
		(end 179.105814 -275.516594)
		(width 0.381)
		(layer "F.Cu")
		(net "GND")
	)
	(segment
		(start 87.31504 -275.080984)
		(end 87.31504 -275.08073)
		(width 0.254)
		(layer "F.Cu")
		(net "GND")
	)
	(segment
		(start 350.292162 -278.336248)
		(end 350.292416 -278.336502)
		(width 0.254)
		(layer "F.Cu")
		(net "GND")
	)
	(segment
		(start 436.928514 -195.616576)
		(end 438.033414 -195.616576)
		(width 0.381)
		(layer "F.Cu")
		(net "GND")
	)
	(segment
		(start 305.443382 -294.216582)
		(end 306.548282 -294.216582)
		(width 0.381)
		(layer "F.Cu")
		(net "GND")
	)
	(segment
		(start 136.075166 -229.808786)
		(end 136.075166 -229.272846)
		(width 0.254)
		(layer "F.Cu")
		(net "GND")
	)
	(segment
		(start 132.315712 -226.553268)
		(end 132.315712 -226.017582)
		(width 0.254)
		(layer "F.Cu")
		(net "GND")
	)
	(segment
		(start 277.607014 -298.466764)
		(end 278.711914 -298.466764)
		(width 0.381)
		(layer "F.Cu")
		(net "GND")
	)
	(segment
		(start 188.988446 -199.01662)
		(end 187.883546 -199.01662)
		(width 0.381)
		(layer "F.Cu")
		(net "GND")
	)
	(segment
		(start 439.923682 -211.766658)
		(end 441.028582 -211.766658)
		(width 0.381)
		(layer "F.Cu")
		(net "GND")
	)
	(segment
		(start 433.484782 -297.616626)
		(end 434.589682 -297.616626)
		(width 0.381)
		(layer "F.Cu")
		(net "GND")
	)
	(segment
		(start 120.438926 -122.496834)
		(end 120.438926 -123.112784)
		(width 0.3556)
		(layer "F.Cu")
		(net "GND")
	)
	(segment
		(start 190.093346 -246.616728)
		(end 188.988446 -246.616728)
		(width 0.381)
		(layer "F.Cu")
		(net "GND")
	)
	(segment
		(start 312.987182 -303.566576)
		(end 314.092082 -303.566576)
		(width 0.381)
		(layer "F.Cu")
		(net "GND")
	)
	(segment
		(start 34.871914 -301.01667)
		(end 33.767014 -301.01667)
		(width 0.381)
		(layer "F.Cu")
		(net "GND")
	)
	(segment
		(start 348.30258 -216.78646)
		(end 348.30258 -216.250774)
		(width 0.254)
		(layer "F.Cu")
		(net "GND")
	)
	(segment
		(start 131.016248 -268.84757)
		(end 131.015994 -269.38351)
		(width 0.2032)
		(layer "F.Cu")
		(net "GND")
	)
	(segment
		(start 286.255714 -317.166752)
		(end 285.150814 -317.166752)
		(width 0.381)
		(layer "F.Cu")
		(net "GND")
	)
	(segment
		(start 290.355782 -299.316648)
		(end 291.460682 -299.316648)
		(width 0.381)
		(layer "F.Cu")
		(net "GND")
	)
	(segment
		(start 240.50371 -247.415558)
		(end 240.50371 -248.011188)
		(width 0.3556)
		(layer "F.Cu")
		(net "GND")
	)
	(segment
		(start 290.355782 -312.91657)
		(end 291.460682 -312.91657)
		(width 0.381)
		(layer "F.Cu")
		(net "GND")
	)
	(segment
		(start 126.676912 -226.017582)
		(end 126.677166 -226.017328)
		(width 0.254)
		(layer "F.Cu")
		(net "GND")
	)
	(segment
		(start 8.74776 -97.236788)
		(end 9.29513 -97.784158)
		(width 0.254)
		(layer "F.Cu")
		(net "GND")
	)
	(segment
		(start 336.399632 -38.880288)
		(end 336.399632 -38.050216)
		(width 0.2032)
		(layer "F.Cu")
		(net "GND")
	)
	(segment
		(start 49.959514 -228.766624)
		(end 51.064414 -228.766624)
		(width 0.381)
		(layer "F.Cu")
		(net "GND")
	)
	(segment
		(start 408.194256 -313.766708)
		(end 406.753314 -313.766708)
		(width 0.381)
		(layer "F.Cu")
		(net "GND")
	)
	(segment
		(start 330.706222 -35.74542)
		(end 330.897738 -35.936936)
		(width 0.2032)
		(layer "F.Cu")
		(net "GND")
	)
	(segment
		(start 444.472314 -244.916706)
		(end 445.577214 -244.916706)
		(width 0.381)
		(layer "F.Cu")
		(net "GND")
	)
	(segment
		(start 409.748482 -247.466612)
		(end 410.853382 -247.466612)
		(width 0.381)
		(layer "F.Cu")
		(net "GND")
	)
	(segment
		(start 346.063316 -286.7533)
		(end 346.063316 -287.288986)
		(width 0.254)
		(layer "F.Cu")
		(net "GND")
	)
	(segment
		(start 405.439372 -206.666592)
		(end 406.753314 -206.666592)
		(width 0.381)
		(layer "F.Cu")
		(net "GND")
	)
	(segment
		(start 304.338482 -216.866724)
		(end 305.443382 -216.866724)
		(width 0.381)
		(layer "F.Cu")
		(net "GND")
	)
	(segment
		(start 27.328114 -301.01667)
		(end 28.433014 -301.01667)
		(width 0.381)
		(layer "F.Cu")
		(net "GND")
	)
	(segment
		(start 332.397608 -59.473846)
		(end 332.397608 -58.850276)
		(width 0.2032)
		(layer "F.Cu")
		(net "GND")
	)
	(segment
		(start 303.875186 -424.585892)
		(end 303.322482 -424.033188)
		(width 0.3556)
		(layer "F.Cu")
		(net "GND")
	)
	(segment
		(start 376.606562 -281.05608)
		(end 376.606816 -281.59202)
		(width 0.2032)
		(layer "F.Cu")
		(net "GND")
	)
	(segment
		(start 278.711914 -217.716608)
		(end 279.816814 -217.716608)
		(width 0.381)
		(layer "F.Cu")
		(net "GND")
	)
	(segment
		(start 121.148094 -276.172676)
		(end 121.148348 -276.708616)
		(width 0.2032)
		(layer "F.Cu")
		(net "GND")
	)
	(segment
		(start 213.81593 -125.821948)
		(end 213.81593 -125.186948)
		(width 0.3556)
		(layer "F.Cu")
		(net "GND")
	)
	(segment
		(start 358.280716 -262.336534)
		(end 358.280716 -262.87222)
		(width 0.254)
		(layer "F.Cu")
		(net "GND")
	)
	(segment
		(start 373.207534 -224.111566)
		(end 373.207534 -223.575626)
		(width 0.2032)
		(layer "F.Cu")
		(net "GND")
	)
	(segment
		(start 211.619846 -203.266802)
		(end 210.514946 -203.266802)
		(width 0.381)
		(layer "F.Cu")
		(net "GND")
	)
	(segment
		(start 262.519414 -295.06672)
		(end 263.624314 -295.06672)
		(width 0.381)
		(layer "F.Cu")
		(net "GND")
	)
	(segment
		(start 44.754546 -295.06672)
		(end 45.859446 -295.06672)
		(width 0.381)
		(layer "F.Cu")
		(net "GND")
	)
	(segment
		(start 53.267102 -12.37488)
		(end 53.267102 -11.26998)
		(width 0.3556)
		(layer "F.Cu")
		(net "GND")
	)
	(segment
		(start 160.170622 -206.666592)
		(end 158.813246 -206.666592)
		(width 0.381)
		(layer "F.Cu")
		(net "GND")
	)
	(segment
		(start 195.427346 -212.616796)
		(end 196.532246 -212.616796)
		(width 0.381)
		(layer "F.Cu")
		(net "GND")
	)
	(segment
		(start 190.093346 -216.016586)
		(end 188.988446 -216.016586)
		(width 0.381)
		(layer "F.Cu")
		(net "GND")
	)
	(segment
		(start 355.930962 -268.56944)
		(end 355.931216 -268.569694)
		(width 0.2032)
		(layer "F.Cu")
		(net "GND")
	)
	(segment
		(start 200.632314 -289.966654)
		(end 201.737214 -289.966654)
		(width 0.381)
		(layer "F.Cu")
		(net "GND")
	)
	(segment
		(start 285.150814 -208.366614)
		(end 286.255714 -208.366614)
		(width 0.381)
		(layer "F.Cu")
		(net "GND")
	)
	(segment
		(start 46.487842 -393.315444)
		(end 46.488096 -393.315698)
		(width 0.4572)
		(layer "F.Cu")
		(net "GND")
	)
	(segment
		(start 45.859446 -233.016806)
		(end 46.964346 -233.016806)
		(width 0.381)
		(layer "F.Cu")
		(net "GND")
	)
	(segment
		(start 188.988446 -223.666558)
		(end 187.883546 -223.666558)
		(width 0.381)
		(layer "F.Cu")
		(net "GND")
	)
	(segment
		(start 263.624314 -273.816572)
		(end 264.729214 -273.816572)
		(width 0.381)
		(layer "F.Cu")
		(net "GND")
	)
	(segment
		(start 346.42298 -242.830858)
		(end 346.42298 -242.295172)
		(width 0.2032)
		(layer "F.Cu")
		(net "GND")
	)
	(segment
		(start 158.813246 -220.266768)
		(end 157.708346 -220.266768)
		(width 0.381)
		(layer "F.Cu")
		(net "GND")
	)
	(segment
		(start 276.373082 -306.96662)
		(end 275.268182 -306.96662)
		(width 0.381)
		(layer "F.Cu")
		(net "GND")
	)
	(segment
		(start 92.844366 -233.06405)
		(end 92.844366 -232.528364)
		(width 0.254)
		(layer "F.Cu")
		(net "GND")
	)
	(segment
		(start 349.24238 -216.250774)
		(end 349.242634 -216.25052)
		(width 0.254)
		(layer "F.Cu")
		(net "GND")
	)
	(segment
		(start 100.832666 -242.017042)
		(end 100.832666 -241.481102)
		(width 0.254)
		(layer "F.Cu")
		(net "GND")
	)
	(segment
		(start 181.47157 -358.534716)
		(end 181.308756 -358.534716)
		(width 0.381)
		(layer "F.Cu")
		(net "GND")
	)
	(segment
		(start 173.900846 -270.416782)
		(end 172.795946 -270.416782)
		(width 0.381)
		(layer "F.Cu")
		(net "GND")
	)
	(segment
		(start 352.641916 -283.497782)
		(end 352.641916 -284.033468)
		(width 0.254)
		(layer "F.Cu")
		(net "GND")
	)
	(segment
		(start 435.823614 -270.416782)
		(end 436.928514 -270.416782)
		(width 0.381)
		(layer "F.Cu")
		(net "GND")
	)
	(segment
		(start 42.415714 -258.516628)
		(end 41.310814 -258.516628)
		(width 0.381)
		(layer "F.Cu")
		(net "GND")
	)
	(segment
		(start 292.694614 -283.166566)
		(end 293.799514 -283.166566)
		(width 0.381)
		(layer "F.Cu")
		(net "GND")
	)
	(segment
		(start 59.842146 -263.616694)
		(end 60.947046 -263.616694)
		(width 0.381)
		(layer "F.Cu")
		(net "GND")
	)
	(segment
		(start 45.859446 -251.716794)
		(end 46.964346 -251.716794)
		(width 0.381)
		(layer "F.Cu")
		(net "GND")
	)
	(segment
		(start 202.971146 -270.416782)
		(end 204.076046 -270.416782)
		(width 0.381)
		(layer "F.Cu")
		(net "GND")
	)
	(segment
		(start 188.988446 -304.416714)
		(end 190.093346 -304.416714)
		(width 0.381)
		(layer "F.Cu")
		(net "GND")
	)
	(segment
		(start 124.437648 -265.592306)
		(end 124.437648 -266.127992)
		(width 0.254)
		(layer "F.Cu")
		(net "GND")
	)
	(segment
		(start 65.047114 -250.866656)
		(end 66.152014 -250.866656)
		(width 0.381)
		(layer "F.Cu")
		(net "GND")
	)
	(segment
		(start 405.648414 -263.616694)
		(end 406.753314 -263.616694)
		(width 0.381)
		(layer "F.Cu")
		(net "GND")
	)
	(segment
		(start 165.252146 -272.116804)
		(end 166.357046 -272.116804)
		(width 0.381)
		(layer "F.Cu")
		(net "GND")
	)
	(segment
		(start 406.753314 -214.316564)
		(end 407.858214 -214.316564)
		(width 0.381)
		(layer "F.Cu")
		(net "GND")
	)
	(segment
		(start 95.773494 -282.683966)
		(end 95.773494 -283.219906)
		(width 0.2032)
		(layer "F.Cu")
		(net "GND")
	)
	(segment
		(start 418.397182 -295.916604)
		(end 417.292282 -295.916604)
		(width 0.381)
		(layer "F.Cu")
		(net "GND")
	)
	(segment
		(start 98.953066 -214.344758)
		(end 98.953066 -213.732618)
		(width 0.254)
		(layer "F.Cu")
		(net "GND")
	)
	(segment
		(start 369.088162 -281.05608)
		(end 369.088162 -281.591512)
		(width 0.254)
		(layer "F.Cu")
		(net "GND")
	)
	(segment
		(start 35.976814 -286.56661)
		(end 34.871914 -286.56661)
		(width 0.381)
		(layer "F.Cu")
		(net "GND")
	)
	(segment
		(start 56.398414 -294.216582)
		(end 57.503314 -294.216582)
		(width 0.381)
		(layer "F.Cu")
		(net "GND")
	)
	(segment
		(start 109.760512 -223.297496)
		(end 109.760512 -222.76181)
		(width 0.254)
		(layer "F.Cu")
		(net "GND")
	)
	(segment
		(start 63.942214 -306.96662)
		(end 65.047114 -306.96662)
		(width 0.381)
		(layer "F.Cu")
		(net "GND")
	)
	(segment
		(start 135.714994 -259.081016)
		(end 135.714994 -259.093462)
		(width 0.2032)
		(layer "F.Cu")
		(net "GND")
	)
	(segment
		(start 86.143592 -337.601306)
		(end 85.715602 -337.173316)
		(width 0.2032)
		(layer "F.Cu")
		(net "GND")
	)
	(segment
		(start 384.015234 -216.25052)
		(end 384.015234 -216.78646)
		(width 0.2032)
		(layer "F.Cu")
		(net "GND")
	)
	(segment
		(start 294.904414 -246.616728)
		(end 293.799514 -246.616728)
		(width 0.381)
		(layer "F.Cu")
		(net "GND")
	)
	(segment
		(start 118.218712 -232.528618)
		(end 118.218966 -232.528364)
		(width 0.254)
		(layer "F.Cu")
		(net "GND")
	)
	(segment
		(start 409.748482 -284.866588)
		(end 410.853382 -284.866588)
		(width 0.381)
		(layer "F.Cu")
		(net "GND")
	)
	(segment
		(start 110.230666 -243.644928)
		(end 110.230666 -243.109496)
		(width 0.254)
		(layer "F.Cu")
		(net "GND")
	)
	(segment
		(start 260.180582 -284.866588)
		(end 259.075682 -284.866588)
		(width 0.381)
		(layer "F.Cu")
		(net "GND")
	)
	(segment
		(start 125.267466 -217.600276)
		(end 125.267466 -217.064336)
		(width 0.254)
		(layer "F.Cu")
		(net "GND")
	)
	(segment
		(start 456.116182 -266.1666)
		(end 455.011282 -266.1666)
		(width 0.381)
		(layer "F.Cu")
		(net "GND")
	)
	(segment
		(start 8.140446 -234.716574)
		(end 9.245346 -234.716574)
		(width 0.381)
		(layer "F.Cu")
		(net "GND")
	)
	(segment
		(start 340.87689 -53.983636)
		(end 341.37727 -54.089046)
		(width 0.2032)
		(layer "F.Cu")
		(net "GND")
	)
	(segment
		(start 104.121712 -221.134178)
		(end 104.121966 -221.133924)
		(width 0.2032)
		(layer "F.Cu")
		(net "GND")
	)
	(segment
		(start 386.83438 -239.57534)
		(end 387.026404 -239.57534)
		(width 0.254)
		(layer "F.Cu")
		(net "GND")
	)
	(segment
		(start 282.811982 -262.76681)
		(end 283.916882 -262.76681)
		(width 0.381)
		(layer "F.Cu")
		(net "GND")
	)
	(segment
		(start 57.503314 -215.166702)
		(end 58.608214 -215.166702)
		(width 0.381)
		(layer "F.Cu")
		(net "GND")
	)
	(segment
		(start 444.472314 -272.116804)
		(end 445.577214 -272.116804)
		(width 0.381)
		(layer "F.Cu")
		(net "GND")
	)
	(segment
		(start 312.987182 -196.466714)
		(end 314.092082 -196.466714)
		(width 0.381)
		(layer "F.Cu")
		(net "GND")
	)
	(segment
		(start 456.116182 -244.066568)
		(end 455.011282 -244.066568)
		(width 0.381)
		(layer "F.Cu")
		(net "GND")
	)
	(segment
		(start 277.607014 -261.916672)
		(end 278.711914 -261.916672)
		(width 0.381)
		(layer "F.Cu")
		(net "GND")
	)
	(segment
		(start 166.357046 -287.416748)
		(end 165.455346 -287.416748)
		(width 0.381)
		(layer "F.Cu")
		(net "GND")
	)
	(segment
		(start 380.365762 -258.802886)
		(end 380.366016 -258.80314)
		(width 0.2032)
		(layer "F.Cu")
		(net "GND")
	)
	(segment
		(start 341.815928 -333.763112)
		(end 341.815928 -333.330804)
		(width 0.2032)
		(layer "F.Cu")
		(net "GND")
	)
	(segment
		(start 113.519712 -242.830858)
		(end 113.519712 -242.29568)
		(width 0.254)
		(layer "F.Cu")
		(net "GND")
	)
	(segment
		(start 171.097448 -416.550348)
		(end 170.462448 -416.550348)
		(width 0.3556)
		(layer "F.Cu")
		(net "GND")
	)
	(segment
		(start 96.603312 -247.714262)
		(end 96.603312 -247.178322)
		(width 0.2032)
		(layer "F.Cu")
		(net "GND")
	)
	(segment
		(start 19.784314 -219.41663)
		(end 18.679414 -219.41663)
		(width 0.381)
		(layer "F.Cu")
		(net "GND")
	)
	(segment
		(start 419.502082 -295.916604)
		(end 418.397182 -295.916604)
		(width 0.381)
		(layer "F.Cu")
		(net "GND")
	)
	(segment
		(start 128.556512 -232.528618)
		(end 128.556766 -232.528364)
		(width 0.254)
		(layer "F.Cu")
		(net "GND")
	)
	(segment
		(start 173.900846 -212.616796)
		(end 172.795946 -212.616796)
		(width 0.381)
		(layer "F.Cu")
		(net "GND")
	)
	(segment
		(start 188.988446 -221.96679)
		(end 187.883546 -221.96679)
		(width 0.381)
		(layer "F.Cu")
		(net "GND")
	)
	(segment
		(start 38.424358 -355.77145)
		(end 38.822884 -355.372924)
		(width 0.2032)
		(layer "F.Cu")
		(net "GND")
	)
	(segment
		(start 250.194064 -87.086694)
		(end 250.194064 -87.543386)
		(width 0.3556)
		(layer "F.Cu")
		(net "GND")
	)
	(segment
		(start 421.840914 -301.866808)
		(end 420.736014 -301.866808)
		(width 0.381)
		(layer "F.Cu")
		(net "GND")
	)
	(segment
		(start 462.555082 -228.766624)
		(end 463.659982 -228.766624)
		(width 0.381)
		(layer "F.Cu")
		(net "GND")
	)
	(segment
		(start 26.223214 -269.566644)
		(end 27.328114 -269.566644)
		(width 0.381)
		(layer "F.Cu")
		(net "GND")
	)
	(segment
		(start 104.701594 -265.592306)
		(end 104.701848 -265.592306)
		(width 0.381)
		(layer "F.Cu")
		(net "GND")
	)
	(segment
		(start 195.427346 -210.916774)
		(end 196.532246 -210.916774)
		(width 0.381)
		(layer "F.Cu")
		(net "GND")
	)
	(segment
		(start 108.820966 -220.041724)
		(end 108.820966 -219.506038)
		(width 0.254)
		(layer "F.Cu")
		(net "GND")
	)
	(segment
		(start 7.035546 -208.366614)
		(end 8.140446 -208.366614)
		(width 0.381)
		(layer "F.Cu")
		(net "GND")
	)
	(segment
		(start 129.606294 -282.683966)
		(end 129.606294 -283.219906)
		(width 0.2032)
		(layer "F.Cu")
		(net "GND")
	)
	(segment
		(start 262.519414 -267.016738)
		(end 263.624314 -267.016738)
		(width 0.381)
		(layer "F.Cu")
		(net "GND")
	)
	(segment
		(start 294.904414 -301.866808)
		(end 293.799514 -301.866808)
		(width 0.381)
		(layer "F.Cu")
		(net "GND")
	)
	(segment
		(start 267.724382 -261.066788)
		(end 268.829282 -261.066788)
		(width 0.381)
		(layer "F.Cu")
		(net "GND")
	)
	(segment
		(start 122.558048 -259.081016)
		(end 122.558048 -259.093462)
		(width 0.254)
		(layer "F.Cu")
		(net "GND")
	)
	(segment
		(start 277.607014 -315.46673)
		(end 278.711914 -315.46673)
		(width 0.381)
		(layer "F.Cu")
		(net "GND")
	)
	(segment
		(start 169.352214 -267.866622)
		(end 170.457114 -267.866622)
		(width 0.381)
		(layer "F.Cu")
		(net "GND")
	)
	(segment
		(start 204.076046 -197.316598)
		(end 205.180946 -197.316598)
		(width 0.381)
		(layer "F.Cu")
		(net "GND")
	)
	(segment
		(start 134.305294 -260.430518)
		(end 134.305548 -260.430772)
		(width 0.2032)
		(layer "F.Cu")
		(net "GND")
	)
	(segment
		(start 125.737366 -231.436164)
		(end 125.737366 -230.900478)
		(width 0.2032)
		(layer "F.Cu")
		(net "GND")
	)
	(segment
		(start 131.75869 -115.585748)
		(end 131.75869 -114.920268)
		(width 0.3556)
		(layer "F.Cu")
		(net "GND")
	)
	(segment
		(start 118.328694 -283.219652)
		(end 118.328948 -283.219906)
		(width 0.254)
		(layer "F.Cu")
		(net "GND")
	)
	(segment
		(start 19.784314 -294.216582)
		(end 20.889214 -294.216582)
		(width 0.381)
		(layer "F.Cu")
		(net "GND")
	)
	(segment
		(start 158.813246 -217.716608)
		(end 157.494732 -217.716608)
		(width 0.381)
		(layer "F.Cu")
		(net "GND")
	)
	(segment
		(start 26.223214 -224.516696)
		(end 27.328114 -224.516696)
		(width 0.381)
		(layer "F.Cu")
		(net "GND")
	)
	(segment
		(start 43.520614 -216.866724)
		(end 42.415714 -216.866724)
		(width 0.381)
		(layer "F.Cu")
		(net "GND")
	)
	(segment
		(start 38.315646 -208.366614)
		(end 37.210746 -208.366614)
		(width 0.381)
		(layer "F.Cu")
		(net "GND")
	)
	(segment
		(start 340.78418 -220.041978)
		(end 340.784434 -220.041724)
		(width 0.254)
		(layer "F.Cu")
		(net "GND")
	)
	(segment
		(start 377.436634 -231.436164)
		(end 377.436634 -230.900478)
		(width 0.2032)
		(layer "F.Cu")
		(net "GND")
	)
	(segment
		(start 376.136916 -283.497782)
		(end 376.136916 -284.033468)
		(width 0.254)
		(layer "F.Cu")
		(net "GND")
	)
	(segment
		(start 445.577214 -225.36658)
		(end 444.472314 -225.36658)
		(width 0.381)
		(layer "F.Cu")
		(net "GND")
	)
	(segment
		(start 381.19558 -220.041978)
		(end 381.19558 -219.506292)
		(width 0.254)
		(layer "F.Cu")
		(net "GND")
	)
	(segment
		(start 202.971146 -285.716726)
		(end 204.076046 -285.716726)
		(width 0.381)
		(layer "F.Cu")
		(net "GND")
	)
	(segment
		(start 115.106704 -361.72775)
		(end 115.716304 -361.72775)
		(width 0.381)
		(layer "F.Cu")
		(net "GND")
	)
	(segment
		(start 449.677282 -305.266598)
		(end 448.572382 -305.266598)
		(width 0.381)
		(layer "F.Cu")
		(net "GND")
	)
	(segment
		(start 181.444646 -244.916706)
		(end 182.549546 -244.916706)
		(width 0.381)
		(layer "F.Cu")
		(net "GND")
	)
	(segment
		(start 429.566832 -11.26998)
		(end 429.566832 -10.16508)
		(width 0.3556)
		(layer "F.Cu")
		(net "GND")
	)
	(segment
		(start 385.534662 -255.825498)
		(end 385.065016 -255.547368)
		(width 0.254)
		(layer "F.Cu")
		(net "GND")
	)
	(segment
		(start 50.274728 -173.789086)
		(end 50.366422 -173.88078)
		(width 0.254)
		(layer "F.Cu")
		(net "GND")
	)
	(segment
		(start 337.134962 -284.311598)
		(end 337.134962 -284.847538)
		(width 0.2032)
		(layer "F.Cu")
		(net "GND")
	)
	(segment
		(start 22.123146 -238.966756)
		(end 23.228046 -238.966756)
		(width 0.381)
		(layer "F.Cu")
		(net "GND")
	)
	(segment
		(start 223.716088 -222.69704)
		(end 223.050608 -222.69704)
		(width 0.381)
		(layer "F.Cu")
		(net "GND")
	)
	(segment
		(start 405.648414 -199.01662)
		(end 406.753314 -199.01662)
		(width 0.381)
		(layer "F.Cu")
		(net "GND")
	)
	(segment
		(start 204.968094 -100.056696)
		(end 203.813918 -100.056696)
		(width 0.3556)
		(layer "F.Cu")
		(net "GND")
	)
	(segment
		(start 106.471466 -224.111566)
		(end 106.471466 -223.575626)
		(width 0.2032)
		(layer "F.Cu")
		(net "GND")
	)
	(segment
		(start 336.085434 -218.414346)
		(end 336.085434 -217.878406)
		(width 0.2032)
		(layer "F.Cu")
		(net "GND")
	)
	(segment
		(start 438.427876 -94.327472)
		(end 439.28792 -94.327472)
		(width 0.3556)
		(layer "F.Cu")
		(net "GND")
	)
	(segment
		(start 173.900846 -265.316716)
		(end 172.795946 -265.316716)
		(width 0.381)
		(layer "F.Cu")
		(net "GND")
	)
	(segment
		(start 15.684246 -309.51678)
		(end 16.789146 -309.51678)
		(width 0.381)
		(layer "F.Cu")
		(net "GND")
	)
	(segment
		(start 130.546094 -279.428194)
		(end 130.546348 -279.964134)
		(width 0.254)
		(layer "F.Cu")
		(net "GND")
	)
	(segment
		(start 290.355782 -277.216616)
		(end 291.460682 -277.216616)
		(width 0.381)
		(layer "F.Cu")
		(net "GND")
	)
	(segment
		(start 90.964512 -229.808786)
		(end 90.964766 -229.808532)
		(width 0.2032)
		(layer "F.Cu")
		(net "GND")
	)
	(segment
		(start 386.474716 -262.336534)
		(end 386.474716 -262.872474)
		(width 0.254)
		(layer "F.Cu")
		(net "GND")
	)
	(segment
		(start 211.619846 -296.766742)
		(end 210.514946 -296.766742)
		(width 0.381)
		(layer "F.Cu")
		(net "GND")
	)
	(segment
		(start 337.495134 -248.528078)
		(end 337.495134 -247.992138)
		(width 0.2032)
		(layer "F.Cu")
		(net "GND")
	)
	(segment
		(start 57.503314 -306.96662)
		(end 58.608214 -306.96662)
		(width 0.381)
		(layer "F.Cu")
		(net "GND")
	)
	(segment
		(start 134.195566 -248.806208)
		(end 134.195566 -249.342148)
		(width 0.2032)
		(layer "F.Cu")
		(net "GND")
	)
	(segment
		(start 354.991162 -275.080476)
		(end 354.991416 -275.08073)
		(width 0.254)
		(layer "F.Cu")
		(net "GND")
	)
	(segment
		(start 49.139094 -170.108372)
		(end 48.508158 -170.108372)
		(width 0.3556)
		(layer "F.Cu")
		(net "GND")
	)
	(segment
		(start 282.811982 -250.866656)
		(end 283.916882 -250.866656)
		(width 0.381)
		(layer "F.Cu")
		(net "GND")
	)
	(segment
		(start 35.976814 -277.216616)
		(end 34.871914 -277.216616)
		(width 0.381)
		(layer "F.Cu")
		(net "GND")
	)
	(segment
		(start 19.784314 -269.566644)
		(end 18.679414 -269.566644)
		(width 0.381)
		(layer "F.Cu")
		(net "GND")
	)
	(segment
		(start 340.78418 -231.436418)
		(end 340.784434 -231.436164)
		(width 0.2032)
		(layer "F.Cu")
		(net "GND")
	)
	(segment
		(start 409.748482 -210.066636)
		(end 410.853382 -210.066636)
		(width 0.381)
		(layer "F.Cu")
		(net "GND")
	)
	(segment
		(start 301.343314 -221.96679)
		(end 302.448214 -221.96679)
		(width 0.381)
		(layer "F.Cu")
		(net "GND")
	)
	(segment
		(start 410.853382 -224.516696)
		(end 411.958282 -224.516696)
		(width 0.381)
		(layer "F.Cu")
		(net "GND")
	)
	(segment
		(start 179.105814 -261.066788)
		(end 178.000914 -261.066788)
		(width 0.381)
		(layer "F.Cu")
		(net "GND")
	)
	(segment
		(start 279.80767 -426.68698)
		(end 279.80767 -425.69638)
		(width 0.3556)
		(layer "F.Cu")
		(net "GND")
	)
	(segment
		(start 218.07424 -107.221274)
		(end 217.82024 -106.967274)
		(width 0.3556)
		(layer "F.Cu")
		(net "GND")
	)
	(segment
		(start 118.44528 -403.794468)
		(end 118.44528 -405.423116)
		(width 0.3556)
		(layer "F.Cu")
		(net "GND")
	)
	(segment
		(start 43.520614 -262.76681)
		(end 42.415714 -262.76681)
		(width 0.381)
		(layer "F.Cu")
		(net "GND")
	)
	(segment
		(start 97.543112 -216.78646)
		(end 97.543112 -216.250774)
		(width 0.254)
		(layer "F.Cu")
		(net "GND")
	)
	(segment
		(start 373.207534 -245.27256)
		(end 373.207534 -244.73662)
		(width 0.2032)
		(layer "F.Cu")
		(net "GND")
	)
	(segment
		(start 99.422966 -241.202972)
		(end 99.422966 -240.667286)
		(width 0.2032)
		(layer "F.Cu")
		(net "GND")
	)
	(segment
		(start 118.218712 -222.76181)
		(end 118.218966 -222.761556)
		(width 0.254)
		(layer "F.Cu")
		(net "GND")
	)
	(segment
		(start 39.420546 -289.11677)
		(end 38.315646 -289.11677)
		(width 0.381)
		(layer "F.Cu")
		(net "GND")
	)
	(segment
		(start 27.328114 -277.216616)
		(end 28.433014 -277.216616)
		(width 0.381)
		(layer "F.Cu")
		(net "GND")
	)
	(segment
		(start 131.27355 -124.234448)
		(end 130.66395 -124.234448)
		(width 0.3556)
		(layer "F.Cu")
		(net "GND")
	)
	(segment
		(start 352.641916 -286.7533)
		(end 352.641916 -287.28924)
		(width 0.254)
		(layer "F.Cu")
		(net "GND")
	)
	(segment
		(start 341.135208 -338.796884)
		(end 341.133176 -338.798916)
		(width 0.381)
		(layer "F.Cu")
		(net "GND")
	)
	(segment
		(start 331.897482 -57.605168)
		(end 331.897482 -57.904888)
		(width 0.2032)
		(layer "F.Cu")
		(net "GND")
	)
	(segment
		(start 448.572382 -247.466612)
		(end 447.467482 -247.466612)
		(width 0.381)
		(layer "F.Cu")
		(net "GND")
	)
	(segment
		(start 296.794682 -228.766624)
		(end 297.899582 -228.766624)
		(width 0.381)
		(layer "F.Cu")
		(net "GND")
	)
	(segment
		(start 184.96788 -96.719898)
		(end 184.20588 -96.719898)
		(width 0.3556)
		(layer "F.Cu")
		(net "GND")
	)
	(segment
		(start 164.018214 -284.866588)
		(end 162.913314 -284.866588)
		(width 0.381)
		(layer "F.Cu")
		(net "GND")
	)
	(segment
		(start 376.966734 -248.528078)
		(end 376.96648 -248.527824)
		(width 0.2032)
		(layer "F.Cu")
		(net "GND")
	)
	(segment
		(start 178.000914 -235.566712)
		(end 176.896014 -235.566712)
		(width 0.381)
		(layer "F.Cu")
		(net "GND")
	)
	(segment
		(start 385.052062 -347.959426)
		(end 385.686554 -347.959426)
		(width 0.381)
		(layer "F.Cu")
		(net "GND")
	)
	(segment
		(start 170.457114 -205.816708)
		(end 171.562014 -205.816708)
		(width 0.381)
		(layer "F.Cu")
		(net "GND")
	)
	(segment
		(start 354.881434 -229.808532)
		(end 354.881434 -229.272846)
		(width 0.2032)
		(layer "F.Cu")
		(net "GND")
	)
	(segment
		(start 409.748482 -224.516696)
		(end 410.853382 -224.516696)
		(width 0.381)
		(layer "F.Cu")
		(net "GND")
	)
	(segment
		(start 443.367414 -278.066754)
		(end 444.472314 -278.066754)
		(width 0.381)
		(layer "F.Cu")
		(net "GND")
	)
	(segment
		(start 215.719914 -219.41663)
		(end 216.824814 -219.41663)
		(width 0.381)
		(layer "F.Cu")
		(net "GND")
	)
	(segment
		(start 56.182514 -312.91657)
		(end 57.503314 -312.91657)
		(width 0.381)
		(layer "F.Cu")
		(net "GND")
	)
	(segment
		(start 48.854614 -238.116618)
		(end 49.959514 -238.116618)
		(width 0.381)
		(layer "F.Cu")
		(net "GND")
	)
	(segment
		(start 53.403246 -315.46673)
		(end 54.508146 -315.46673)
		(width 0.381)
		(layer "F.Cu")
		(net "GND")
	)
	(segment
		(start 358.280716 -262.87222)
		(end 358.280462 -262.872474)
		(width 0.254)
		(layer "F.Cu")
		(net "GND")
	)
	(segment
		(start 348.30258 -223.297496)
		(end 348.30258 -222.76181)
		(width 0.254)
		(layer "F.Cu")
		(net "GND")
	)
	(segment
		(start 431.202592 -117.785896)
		(end 431.202592 -118.415054)
		(width 0.381)
		(layer "F.Cu")
		(net "GND")
	)
	(segment
		(start 360.61904 -396.984728)
		(end 361.323636 -396.984728)
		(width 0.3556)
		(layer "F.Cu")
		(net "GND")
	)
	(segment
		(start 196.532246 -203.266802)
		(end 197.637146 -203.266802)
		(width 0.381)
		(layer "F.Cu")
		(net "GND")
	)
	(segment
		(start 335.725262 -261.244842)
		(end 335.725262 -260.708902)
		(width 0.18034)
		(layer "F.Cu")
		(net "GND")
	)
	(segment
		(start 459.559914 -300.166786)
		(end 460.664814 -300.166786)
		(width 0.381)
		(layer "F.Cu")
		(net "GND")
	)
	(segment
		(start 105.641648 -275.35886)
		(end 105.641648 -275.8948)
		(width 0.2032)
		(layer "F.Cu")
		(net "GND")
	)
	(segment
		(start 54.508146 -267.016738)
		(end 53.403246 -267.016738)
		(width 0.3556)
		(layer "F.Cu")
		(net "GND")
	)
	(segment
		(start 421.840914 -212.616796)
		(end 422.945814 -212.616796)
		(width 0.381)
		(layer "F.Cu")
		(net "GND")
	)
	(segment
		(start 368.618516 -268.84757)
		(end 368.618262 -269.38351)
		(width 0.254)
		(layer "F.Cu")
		(net "GND")
	)
	(segment
		(start 348.412562 -264.778236)
		(end 348.412562 -265.313922)
		(width 0.254)
		(layer "F.Cu")
		(net "GND")
	)
	(segment
		(start 456.116182 -228.766624)
		(end 455.011282 -228.766624)
		(width 0.381)
		(layer "F.Cu")
		(net "GND")
	)
	(segment
		(start 129.136648 -287.288986)
		(end 129.136394 -287.28924)
		(width 0.254)
		(layer "F.Cu")
		(net "GND")
	)
	(segment
		(start 204.076046 -278.066754)
		(end 205.180946 -278.066754)
		(width 0.381)
		(layer "F.Cu")
		(net "GND")
	)
	(segment
		(start 43.520614 -316.316614)
		(end 42.415714 -316.316614)
		(width 0.381)
		(layer "F.Cu")
		(net "GND")
	)
	(segment
		(start 59.842146 -300.166786)
		(end 60.947046 -300.166786)
		(width 0.381)
		(layer "F.Cu")
		(net "GND")
	)
	(segment
		(start 358.280716 -256.361184)
		(end 358.280462 -256.361438)
		(width 0.254)
		(layer "F.Cu")
		(net "GND")
	)
	(segment
		(start 340.78418 -226.017582)
		(end 340.784434 -226.017328)
		(width 0.254)
		(layer "F.Cu")
		(net "GND")
	)
	(segment
		(start 254.975614 -261.916672)
		(end 256.080514 -261.916672)
		(width 0.381)
		(layer "F.Cu")
		(net "GND")
	)
	(segment
		(start 96.713294 -289.195002)
		(end 96.713294 -289.807142)
		(width 0.2032)
		(layer "F.Cu")
		(net "GND")
	)
	(segment
		(start 418.397182 -299.316648)
		(end 419.502082 -299.316648)
		(width 0.381)
		(layer "F.Cu")
		(net "GND")
	)
	(segment
		(start 412.956756 -11.26998)
		(end 412.956756 -10.16508)
		(width 0.3556)
		(layer "F.Cu")
		(net "GND")
	)
	(segment
		(start 365.708184 -338.328508)
		(end 365.708184 -337.955382)
		(width 0.381)
		(layer "F.Cu")
		(net "GND")
	)
	(segment
		(start 89.085166 -220.041724)
		(end 89.085166 -219.506038)
		(width 0.254)
		(layer "F.Cu")
		(net "GND")
	)
	(segment
		(start 136.655048 -273.730974)
		(end 136.184894 -273.453098)
		(width 0.2032)
		(layer "F.Cu")
		(net "GND")
	)
	(segment
		(start 165.08222 -436.893208)
		(end 165.16096 -436.971948)
		(width 0.3556)
		(layer "F.Cu")
		(net "GND")
	)
	(segment
		(start 178.000914 -247.466612)
		(end 176.896014 -247.466612)
		(width 0.381)
		(layer "F.Cu")
		(net "GND")
	)
	(segment
		(start 109.760766 -229.808532)
		(end 109.760766 -229.272846)
		(width 0.2032)
		(layer "F.Cu")
		(net "GND")
	)
	(segment
		(start 48.962818 -358.991408)
		(end 48.501046 -358.529636)
		(width 0.381)
		(layer "F.Cu")
		(net "GND")
	)
	(segment
		(start 456.179936 -380.085854)
		(end 456.621388 -380.527306)
		(width 0.381)
		(layer "F.Cu")
		(net "GND")
	)
	(segment
		(start 190.01359 -70.185788)
		(end 190.01359 -70.851268)
		(width 0.3556)
		(layer "F.Cu")
		(net "GND")
	)
	(segment
		(start 410.853382 -232.166668)
		(end 411.958282 -232.166668)
		(width 0.381)
		(layer "F.Cu")
		(net "GND")
	)
	(segment
		(start 355.461316 -270.475456)
		(end 355.461316 -271.011142)
		(width 0.2032)
		(layer "F.Cu")
		(net "GND")
	)
	(segment
		(start 87.785194 -283.497782)
		(end 87.785194 -284.033722)
		(width 0.254)
		(layer "F.Cu")
		(net "GND")
	)
	(segment
		(start 30.771846 -236.416596)
		(end 31.876746 -236.416596)
		(width 0.381)
		(layer "F.Cu")
		(net "GND")
	)
	(segment
		(start 108.3691 -29.842714)
		(end 108.9787 -29.842714)
		(width 0.3556)
		(layer "F.Cu")
		(net "GND")
	)
	(segment
		(start 100.832666 -214.344758)
		(end 100.832666 -213.732618)
		(width 0.254)
		(layer "F.Cu")
		(net "GND")
	)
	(segment
		(start 50.145442 -161.415984)
		(end 50.360834 -161.200592)
		(width 0.381)
		(layer "F.Cu")
		(net "GND")
	)
	(segment
		(start 102.464616 -334.191102)
		(end 102.036626 -333.763112)
		(width 0.2032)
		(layer "F.Cu")
		(net "GND")
	)
	(segment
		(start 180.776626 -416.503104)
		(end 181.407562 -416.503104)
		(width 0.3556)
		(layer "F.Cu")
		(net "GND")
	)
	(segment
		(start 133.835648 -278.614378)
		(end 133.835394 -279.150318)
		(width 0.254)
		(layer "F.Cu")
		(net "GND")
	)
	(segment
		(start 396.415006 -60.749942)
		(end 396.20444 -60.960508)
		(width 0.254)
		(layer "F.Cu")
		(net "GND")
	)
	(segment
		(start 276.373082 -264.466578)
		(end 275.268182 -264.466578)
		(width 0.381)
		(layer "F.Cu")
		(net "GND")
	)
	(segment
		(start 214.615014 -232.166668)
		(end 215.719914 -232.166668)
		(width 0.381)
		(layer "F.Cu")
		(net "GND")
	)
	(segment
		(start 262.519414 -317.166752)
		(end 263.624314 -317.166752)
		(width 0.381)
		(layer "F.Cu")
		(net "GND")
	)
	(segment
		(start 378.956316 -272.103342)
		(end 378.956062 -272.639282)
		(width 0.2032)
		(layer "F.Cu")
		(net "GND")
	)
	(segment
		(start 347.36278 -228.1809)
		(end 347.36278 -227.64496)
		(width 0.2032)
		(layer "F.Cu")
		(net "GND")
	)
	(segment
		(start 130.076448 -257.45313)
		(end 130.076194 -257.98907)
		(width 0.2032)
		(layer "F.Cu")
		(net "GND")
	)
	(segment
		(start 277.607014 -203.266802)
		(end 278.711914 -203.266802)
		(width 0.381)
		(layer "F.Cu")
		(net "GND")
	)
	(segment
		(start 278.711914 -301.866808)
		(end 277.607014 -301.866808)
		(width 0.381)
		(layer "F.Cu")
		(net "GND")
	)
	(segment
		(start 132.895848 -263.96442)
		(end 132.895848 -264.50036)
		(width 0.2032)
		(layer "F.Cu")
		(net "GND")
	)
	(segment
		(start 169.624248 -354.029264)
		(end 169.297096 -354.029264)
		(width 0.2032)
		(layer "F.Cu")
		(net "GND")
	)
	(segment
		(start 363.33938 -220.041978)
		(end 363.339634 -220.041724)
		(width 0.254)
		(layer "F.Cu")
		(net "GND")
	)
	(segment
		(start 350.652334 -233.87812)
		(end 350.65208 -233.877866)
		(width 0.2032)
		(layer "F.Cu")
		(net "GND")
	)
	(segment
		(start 370.967762 -268.033754)
		(end 370.967762 -268.569694)
		(width 0.254)
		(layer "F.Cu")
		(net "GND")
	)
	(segment
		(start 367.019078 -334.191102)
		(end 366.725454 -334.191102)
		(width 0.2032)
		(layer "F.Cu")
		(net "GND")
	)
	(segment
		(start 415.792412 -367.231676)
		(end 415.269172 -367.231676)
		(width 0.381)
		(layer "F.Cu")
		(net "GND")
	)
	(segment
		(start 126.677166 -228.180646)
		(end 126.677166 -227.64496)
		(width 0.2032)
		(layer "F.Cu")
		(net "GND")
	)
	(segment
		(start 452.016114 -313.766708)
		(end 450.911214 -313.766708)
		(width 0.381)
		(layer "F.Cu")
		(net "GND")
	)
	(segment
		(start 436.928514 -251.716794)
		(end 438.033414 -251.716794)
		(width 0.381)
		(layer "F.Cu")
		(net "GND")
	)
	(segment
		(start 161.697924 -216.90457)
		(end 161.628328 -216.90457)
		(width 0.381)
		(layer "F.Cu")
		(net "GND")
	)
	(segment
		(start 354.41128 -232.250234)
		(end 354.41128 -231.714548)
		(width 0.2032)
		(layer "F.Cu")
		(net "GND")
	)
	(segment
		(start 453.121014 -201.56678)
		(end 452.016114 -201.56678)
		(width 0.381)
		(layer "F.Cu")
		(net "GND")
	)
	(segment
		(start 106.581448 -272.639028)
		(end 106.581194 -272.639282)
		(width 0.2032)
		(layer "F.Cu")
		(net "GND")
	)
	(segment
		(start 125.847094 -258.802886)
		(end 125.847348 -258.80314)
		(width 0.2032)
		(layer "F.Cu")
		(net "GND")
	)
	(segment
		(start 414.297114 -197.316598)
		(end 415.402014 -197.316598)
		(width 0.381)
		(layer "F.Cu")
		(net "GND")
	)
	(segment
		(start 26.223214 -202.416664)
		(end 27.328114 -202.416664)
		(width 0.381)
		(layer "F.Cu")
		(net "GND")
	)
	(segment
		(start 328.244962 -45.949108)
		(end 327.829926 -45.448728)
		(width 0.1778)
		(layer "F.Cu")
		(net "GND")
	)
	(segment
		(start 38.45687 -11.26998)
		(end 38.45687 -12.37488)
		(width 0.3556)
		(layer "F.Cu")
		(net "GND")
	)
	(segment
		(start 122.558048 -284.033468)
		(end 122.557794 -284.033722)
		(width 0.254)
		(layer "F.Cu")
		(net "GND")
	)
	(segment
		(start 109.400594 -265.592306)
		(end 109.400594 -266.127992)
		(width 0.254)
		(layer "F.Cu")
		(net "GND")
	)
	(segment
		(start 195.427346 -216.016586)
		(end 196.532246 -216.016586)
		(width 0.381)
		(layer "F.Cu")
		(net "GND")
	)
	(segment
		(start 443.367414 -309.51678)
		(end 444.472314 -309.51678)
		(width 0.381)
		(layer "F.Cu")
		(net "GND")
	)
	(segment
		(start 376.966734 -237.133892)
		(end 376.966734 -236.597952)
		(width 0.2032)
		(layer "F.Cu")
		(net "GND")
	)
	(segment
		(start 129.136648 -278.614378)
		(end 129.136394 -279.150318)
		(width 0.254)
		(layer "F.Cu")
		(net "GND")
	)
	(segment
		(start 444.472314 -300.166786)
		(end 443.367414 -300.166786)
		(width 0.381)
		(layer "F.Cu")
		(net "GND")
	)
	(segment
		(start 340.894162 -266.405868)
		(end 340.894416 -266.406122)
		(width 0.2032)
		(layer "F.Cu")
		(net "GND")
	)
	(segment
		(start 381.775716 -287.288986)
		(end 381.775462 -287.28924)
		(width 0.254)
		(layer "F.Cu")
		(net "GND")
	)
	(segment
		(start 19.769582 -428.424086)
		(end 19.769582 -429.047148)
		(width 0.3556)
		(layer "F.Cu")
		(net "GND")
	)
	(segment
		(start 348.77248 -238.76127)
		(end 348.77248 -238.225584)
		(width 0.2032)
		(layer "F.Cu")
		(net "GND")
	)
	(segment
		(start 339.84438 -220.041978)
		(end 339.844634 -220.041724)
		(width 0.254)
		(layer "F.Cu")
		(net "GND")
	)
	(segment
		(start 185.544714 -261.066788)
		(end 184.439814 -261.066788)
		(width 0.381)
		(layer "F.Cu")
		(net "GND")
	)
	(segment
		(start 133.725666 -227.367084)
		(end 133.725666 -226.831144)
		(width 0.2032)
		(layer "F.Cu")
		(net "GND")
	)
	(segment
		(start 377.43638 -216.250774)
		(end 377.436634 -216.25052)
		(width 0.254)
		(layer "F.Cu")
		(net "GND")
	)
	(segment
		(start 91.544648 -268.84757)
		(end 91.544648 -269.38351)
		(width 0.2032)
		(layer "F.Cu")
		(net "GND")
	)
	(segment
		(start 42.415714 -235.566712)
		(end 41.310814 -235.566712)
		(width 0.381)
		(layer "F.Cu")
		(net "GND")
	)
	(segment
		(start 94.833694 -289.195002)
		(end 94.833694 -289.807142)
		(width 0.2032)
		(layer "F.Cu")
		(net "GND")
	)
	(segment
		(start 432.379882 -294.216582)
		(end 433.484782 -294.216582)
		(width 0.381)
		(layer "F.Cu")
		(net "GND")
	)
	(segment
		(start 282.811982 -247.466612)
		(end 283.916882 -247.466612)
		(width 0.381)
		(layer "F.Cu")
		(net "GND")
	)
	(segment
		(start 429.384714 -210.916774)
		(end 430.489614 -210.916774)
		(width 0.381)
		(layer "F.Cu")
		(net "GND")
	)
	(segment
		(start 96.133666 -227.367084)
		(end 96.133666 -226.831144)
		(width 0.2032)
		(layer "F.Cu")
		(net "GND")
	)
	(segment
		(start 108.737146 -402.915628)
		(end 108.45038 -402.628862)
		(width 0.3556)
		(layer "F.Cu")
		(net "GND")
	)
	(segment
		(start 458.455014 -309.51678)
		(end 459.559914 -309.51678)
		(width 0.381)
		(layer "F.Cu")
		(net "GND")
	)
	(segment
		(start 150.54834 -39.710868)
		(end 151.8158 -39.710868)
		(width 0.3556)
		(layer "F.Cu")
		(net "GND")
	)
	(segment
		(start 94.833694 -272.917158)
		(end 94.833694 -273.453098)
		(width 0.2032)
		(layer "F.Cu")
		(net "GND")
	)
	(segment
		(start 421.840914 -300.166786)
		(end 420.736014 -300.166786)
		(width 0.381)
		(layer "F.Cu")
		(net "GND")
	)
	(segment
		(start 351.702116 -283.497782)
		(end 351.702116 -284.033468)
		(width 0.254)
		(layer "F.Cu")
		(net "GND")
	)
	(segment
		(start 88.145366 -221.669864)
		(end 88.145366 -221.133924)
		(width 0.254)
		(layer "F.Cu")
		(net "GND")
	)
	(segment
		(start 384.565398 -260.307836)
		(end 384.4671 -260.31063)
		(width 0.088646)
		(layer "F.Cu")
		(net "GND")
	)
	(segment
		(start 259.075682 -235.566712)
		(end 260.180582 -235.566712)
		(width 0.381)
		(layer "F.Cu")
		(net "GND")
	)
	(segment
		(start 126.676912 -242.295172)
		(end 126.677166 -242.294918)
		(width 0.2032)
		(layer "F.Cu")
		(net "GND")
	)
	(segment
		(start 377.076716 -287.288986)
		(end 377.076462 -287.28924)
		(width 0.254)
		(layer "F.Cu")
		(net "GND")
	)
	(segment
		(start 459.559914 -250.016772)
		(end 458.455014 -250.016772)
		(width 0.381)
		(layer "F.Cu")
		(net "GND")
	)
	(segment
		(start 132.895848 -265.592306)
		(end 132.895848 -266.127992)
		(width 0.254)
		(layer "F.Cu")
		(net "GND")
	)
	(segment
		(start 108.956348 -102.293166)
		(end 109.591348 -102.293166)
		(width 0.3556)
		(layer "F.Cu")
		(net "GND")
	)
	(segment
		(start 413.192214 -195.616576)
		(end 414.297114 -195.616576)
		(width 0.381)
		(layer "F.Cu")
		(net "GND")
	)
	(segment
		(start 308.887114 -216.016586)
		(end 309.992014 -216.016586)
		(width 0.381)
		(layer "F.Cu")
		(net "GND")
	)
	(segment
		(start 15.684246 -300.166786)
		(end 16.789146 -300.166786)
		(width 0.381)
		(layer "F.Cu")
		(net "GND")
	)
	(segment
		(start 27.328114 -258.516628)
		(end 28.433014 -258.516628)
		(width 0.381)
		(layer "F.Cu")
		(net "GND")
	)
	(segment
		(start 304.338482 -198.166736)
		(end 305.443382 -198.166736)
		(width 0.381)
		(layer "F.Cu")
		(net "GND")
	)
	(segment
		(start 77.107542 -345.802712)
		(end 77.181202 -345.802712)
		(width 0.254)
		(layer "F.Cu")
		(net "GND")
	)
	(segment
		(start 432.379882 -198.166736)
		(end 433.484782 -198.166736)
		(width 0.381)
		(layer "F.Cu")
		(net "GND")
	)
	(segment
		(start 382.135634 -240.667286)
		(end 382.135634 -241.203226)
		(width 0.2032)
		(layer "F.Cu")
		(net "GND")
	)
	(segment
		(start 186.649614 -310.366664)
		(end 185.544714 -310.366664)
		(width 0.381)
		(layer "F.Cu")
		(net "GND")
	)
	(segment
		(start 289.250882 -294.216582)
		(end 290.355782 -294.216582)
		(width 0.381)
		(layer "F.Cu")
		(net "GND")
	)
	(segment
		(start 91.544648 -275.894546)
		(end 91.544394 -275.8948)
		(width 0.2032)
		(layer "F.Cu")
		(net "GND")
	)
	(segment
		(start 443.367414 -238.966756)
		(end 444.472314 -238.966756)
		(width 0.381)
		(layer "F.Cu")
		(net "GND")
	)
	(segment
		(start 332.397608 -58.020204)
		(end 332.397608 -58.850276)
		(width 0.254)
		(layer "F.Cu")
		(net "GND")
	)
	(segment
		(start 89.664794 -257.45313)
		(end 89.664794 -257.98907)
		(width 0.2032)
		(layer "F.Cu")
		(net "GND")
	)
	(segment
		(start 363.809534 -220.855794)
		(end 363.809534 -220.319854)
		(width 0.2032)
		(layer "F.Cu")
		(net "GND")
	)
	(segment
		(start 426.73016 -144.075658)
		(end 425.71416 -144.075658)
		(width 0.3556)
		(layer "F.Cu")
		(net "GND")
	)
	(segment
		(start 202.971146 -263.616694)
		(end 204.076046 -263.616694)
		(width 0.381)
		(layer "F.Cu")
		(net "GND")
	)
	(segment
		(start 164.12083 -46.954948)
		(end 163.18992 -46.954948)
		(width 0.3556)
		(layer "F.Cu")
		(net "GND")
	)
	(segment
		(start 307.759862 -313.766708)
		(end 308.887114 -313.766708)
		(width 0.381)
		(layer "F.Cu")
		(net "GND")
	)
	(segment
		(start 179.105814 -221.116652)
		(end 178.000914 -221.116652)
		(width 0.381)
		(layer "F.Cu")
		(net "GND")
	)
	(segment
		(start 45.859446 -273.816572)
		(end 46.964346 -273.816572)
		(width 0.381)
		(layer "F.Cu")
		(net "GND")
	)
	(segment
		(start 376.68835 -342.270334)
		(end 377.322842 -342.270334)
		(width 0.381)
		(layer "F.Cu")
		(net "GND")
	)
	(segment
		(start 180.555646 -115.375436)
		(end 180.955696 -115.775486)
		(width 0.3556)
		(layer "F.Cu")
		(net "GND")
	)
	(segment
		(start 448.572382 -264.466578)
		(end 447.467482 -264.466578)
		(width 0.381)
		(layer "F.Cu")
		(net "GND")
	)
	(segment
		(start 418.397182 -262.76681)
		(end 417.292282 -262.76681)
		(width 0.381)
		(layer "F.Cu")
		(net "GND")
	)
	(segment
		(start 338.544916 -278.614378)
		(end 338.544662 -279.150318)
		(width 0.2032)
		(layer "F.Cu")
		(net "GND")
	)
	(segment
		(start 328.244962 -50.951384)
		(end 327.41489 -50.951384)
		(width 0.254)
		(layer "F.Cu")
		(net "GND")
	)
	(segment
		(start 85.325712 -232.528364)
		(end 85.325712 -233.064304)
		(width 0.2032)
		(layer "F.Cu")
		(net "GND")
	)
	(segment
		(start 271.168114 -304.416714)
		(end 270.063214 -304.416714)
		(width 0.381)
		(layer "F.Cu")
		(net "GND")
	)
	(segment
		(start 338.90458 -222.76181)
		(end 338.904834 -222.761556)
		(width 0.254)
		(layer "F.Cu")
		(net "GND")
	)
	(segment
		(start 175.005746 -263.616694)
		(end 173.900846 -263.616694)
		(width 0.381)
		(layer "F.Cu")
		(net "GND")
	)
	(segment
		(start 457.221082 -299.316648)
		(end 456.116182 -299.316648)
		(width 0.381)
		(layer "F.Cu")
		(net "GND")
	)
	(segment
		(start 53.403246 -290.816792)
		(end 54.508146 -290.816792)
		(width 0.381)
		(layer "F.Cu")
		(net "GND")
	)
	(segment
		(start 308.887114 -258.516628)
		(end 307.782214 -258.516628)
		(width 0.381)
		(layer "F.Cu")
		(net "GND")
	)
	(segment
		(start 429.384714 -261.916672)
		(end 430.489614 -261.916672)
		(width 0.381)
		(layer "F.Cu")
		(net "GND")
	)
	(segment
		(start 424.836082 -194.766692)
		(end 425.940982 -194.766692)
		(width 0.381)
		(layer "F.Cu")
		(net "GND")
	)
	(segment
		(start 395.413738 -149.69236)
		(end 396.084298 -149.69236)
		(width 0.3556)
		(layer "F.Cu")
		(net "GND")
	)
	(segment
		(start 11.135614 -228.766624)
		(end 12.240514 -228.766624)
		(width 0.381)
		(layer "F.Cu")
		(net "GND")
	)
	(segment
		(start 216.6874 -104.33304)
		(end 217.637868 -104.33304)
		(width 0.3556)
		(layer "F.Cu")
		(net "GND")
	)
	(segment
		(start 169.352214 -295.916604)
		(end 170.457114 -295.916604)
		(width 0.381)
		(layer "F.Cu")
		(net "GND")
	)
	(segment
		(start 374.257316 -255.825498)
		(end 374.257316 -256.361184)
		(width 0.254)
		(layer "F.Cu")
		(net "GND")
	)
	(segment
		(start 166.351458 -134.17677)
		(end 167.064436 -134.17677)
		(width 0.3556)
		(layer "F.Cu")
		(net "GND")
	)
	(segment
		(start 201.8284 -92.23375)
		(end 201.8284 -91.5924)
		(width 0.3556)
		(layer "F.Cu")
		(net "GND")
	)
	(segment
		(start 370.388134 -243.644928)
		(end 370.38788 -243.644674)
		(width 0.254)
		(layer "F.Cu")
		(net "GND")
	)
	(segment
		(start 59.842146 -260.21665)
		(end 60.947046 -260.21665)
		(width 0.381)
		(layer "F.Cu")
		(net "GND")
	)
	(segment
		(start 12.240514 -258.516628)
		(end 13.345414 -258.516628)
		(width 0.381)
		(layer "F.Cu")
		(net "GND")
	)
	(segment
		(start 120.77827 -423.479468)
		(end 121.38787 -423.479468)
		(width 0.3556)
		(layer "F.Cu")
		(net "GND")
	)
	(segment
		(start 333.375762 -264.778236)
		(end 333.845662 -264.50036)
		(width 0.254)
		(layer "F.Cu")
		(net "GND")
	)
	(segment
		(start 29.666946 -246.616728)
		(end 30.771846 -246.616728)
		(width 0.381)
		(layer "F.Cu")
		(net "GND")
	)
	(segment
		(start 39.420546 -208.366614)
		(end 38.315646 -208.366614)
		(width 0.381)
		(layer "F.Cu")
		(net "GND")
	)
	(segment
		(start 212.724746 -287.416748)
		(end 211.619846 -287.416748)
		(width 0.381)
		(layer "F.Cu")
		(net "GND")
	)
	(segment
		(start 307.782214 -281.466798)
		(end 308.887114 -281.466798)
		(width 0.381)
		(layer "F.Cu")
		(net "GND")
	)
	(segment
		(start 15.684246 -265.316716)
		(end 16.789146 -265.316716)
		(width 0.381)
		(layer "F.Cu")
		(net "GND")
	)
	(segment
		(start 120.678194 -264.500106)
		(end 120.678194 -264.50036)
		(width 0.2032)
		(layer "F.Cu")
		(net "GND")
	)
	(segment
		(start 337.49488 -237.133638)
		(end 337.49488 -236.597952)
		(width 0.254)
		(layer "F.Cu")
		(net "GND")
	)
	(segment
		(start 110.23092 -250.15571)
		(end 110.23092 -249.620278)
		(width 0.254)
		(layer "F.Cu")
		(net "GND")
	)
	(segment
		(start 336.555334 -217.600276)
		(end 336.555334 -217.06459)
		(width 0.2032)
		(layer "F.Cu")
		(net "GND")
	)
	(segment
		(start 194.33413 -353.761548)
		(end 195.22948 -353.761548)
		(width 0.3556)
		(layer "F.Cu")
		(net "GND")
	)
	(segment
		(start 12.240514 -314.616592)
		(end 13.345414 -314.616592)
		(width 0.381)
		(layer "F.Cu")
		(net "GND")
	)
	(segment
		(start 56.867044 -9.424924)
		(end 56.867044 -8.320024)
		(width 0.3556)
		(layer "F.Cu")
		(net "GND")
	)
	(segment
		(start 99.46386 -100.073968)
		(end 99.97186 -100.073968)
		(width 0.3556)
		(layer "F.Cu")
		(net "GND")
	)
	(segment
		(start 207.071214 -297.616626)
		(end 208.176114 -297.616626)
		(width 0.381)
		(layer "F.Cu")
		(net "GND")
	)
	(segment
		(start 59.842146 -270.416782)
		(end 60.947046 -270.416782)
		(width 0.381)
		(layer "F.Cu")
		(net "GND")
	)
	(segment
		(start 296.794682 -194.766692)
		(end 297.899582 -194.766692)
		(width 0.381)
		(layer "F.Cu")
		(net "GND")
	)
	(segment
		(start 166.357046 -270.416782)
		(end 167.461946 -270.416782)
		(width 0.381)
		(layer "F.Cu")
		(net "GND")
	)
	(segment
		(start 8.140446 -203.266802)
		(end 9.245346 -203.266802)
		(width 0.381)
		(layer "F.Cu")
		(net "GND")
	)
	(segment
		(start 39.420546 -242.3668)
		(end 38.315646 -242.3668)
		(width 0.381)
		(layer "F.Cu")
		(net "GND")
	)
	(segment
		(start 297.899582 -213.46668)
		(end 299.004482 -213.46668)
		(width 0.381)
		(layer "F.Cu")
		(net "GND")
	)
	(segment
		(start 162.913314 -266.1666)
		(end 164.018214 -266.1666)
		(width 0.381)
		(layer "F.Cu")
		(net "GND")
	)
	(segment
		(start 351.231962 -279.428194)
		(end 351.231962 -279.964134)
		(width 0.2032)
		(layer "F.Cu")
		(net "GND")
	)
	(segment
		(start 377.546362 -271.289272)
		(end 377.546616 -271.825212)
		(width 0.2032)
		(layer "F.Cu")
		(net "GND")
	)
	(segment
		(start 435.823614 -244.916706)
		(end 436.928514 -244.916706)
		(width 0.381)
		(layer "F.Cu")
		(net "GND")
	)
	(segment
		(start 405.648414 -221.96679)
		(end 406.753314 -221.96679)
		(width 0.381)
		(layer "F.Cu")
		(net "GND")
	)
	(segment
		(start 34.871914 -244.066568)
		(end 35.976814 -244.066568)
		(width 0.381)
		(layer "F.Cu")
		(net "GND")
	)
	(segment
		(start 439.923682 -230.466646)
		(end 441.028582 -230.466646)
		(width 0.381)
		(layer "F.Cu")
		(net "GND")
	)
	(segment
		(start 334.205834 -245.545864)
		(end 334.205834 -245.55069)
		(width 0.2032)
		(layer "F.Cu")
		(net "GND")
	)
	(segment
		(start 328.53122 -21.866098)
		(end 328.53122 -21.354288)
		(width 0.3556)
		(layer "F.Cu")
		(net "GND")
	)
	(segment
		(start 301.343314 -270.416782)
		(end 302.448214 -270.416782)
		(width 0.381)
		(layer "F.Cu")
		(net "GND")
	)
	(segment
		(start 56.398414 -245.76659)
		(end 57.503314 -245.76659)
		(width 0.381)
		(layer "F.Cu")
		(net "GND")
	)
	(segment
		(start 355.461316 -284.033468)
		(end 355.461062 -284.033722)
		(width 0.254)
		(layer "F.Cu")
		(net "GND")
	)
	(segment
		(start 335.255362 -274.54479)
		(end 334.785462 -274.266914)
		(width 0.2032)
		(layer "F.Cu")
		(net "GND")
	)
	(segment
		(start 378.956316 -262.336534)
		(end 378.956062 -262.872474)
		(width 0.2032)
		(layer "F.Cu")
		(net "GND")
	)
	(segment
		(start 90.964766 -220.041724)
		(end 90.964766 -219.506038)
		(width 0.254)
		(layer "F.Cu")
		(net "GND")
	)
	(segment
		(start 261.285482 -271.266666)
		(end 260.180582 -271.266666)
		(width 0.381)
		(layer "F.Cu")
		(net "GND")
	)
	(segment
		(start 98.592894 -282.683966)
		(end 98.592894 -283.219906)
		(width 0.2032)
		(layer "F.Cu")
		(net "GND")
	)
	(segment
		(start 54.508146 -212.616796)
		(end 53.403246 -212.616796)
		(width 0.381)
		(layer "F.Cu")
		(net "GND")
	)
	(segment
		(start 420.736014 -233.016806)
		(end 421.840914 -233.016806)
		(width 0.381)
		(layer "F.Cu")
		(net "GND")
	)
	(segment
		(start 308.887114 -301.866808)
		(end 309.992014 -301.866808)
		(width 0.381)
		(layer "F.Cu")
		(net "GND")
	)
	(segment
		(start 405.648414 -195.616576)
		(end 406.753314 -195.616576)
		(width 0.381)
		(layer "F.Cu")
		(net "GND")
	)
	(segment
		(start 410.853382 -247.466612)
		(end 411.958282 -247.466612)
		(width 0.381)
		(layer "F.Cu")
		(net "GND")
	)
	(segment
		(start 297.899582 -261.066788)
		(end 299.004482 -261.066788)
		(width 0.381)
		(layer "F.Cu")
		(net "GND")
	)
	(segment
		(start 27.328114 -232.166668)
		(end 28.433014 -232.166668)
		(width 0.381)
		(layer "F.Cu")
		(net "GND")
	)
	(segment
		(start 387.057646 -248.680478)
		(end 388.003034 -248.680478)
		(width 0.2032)
		(layer "F.Cu")
		(net "GND")
	)
	(segment
		(start 99.422712 -242.295172)
		(end 99.422966 -242.294918)
		(width 0.2032)
		(layer "F.Cu")
		(net "GND")
	)
	(segment
		(start 24.332946 -287.416748)
		(end 23.228046 -287.416748)
		(width 0.381)
		(layer "F.Cu")
		(net "GND")
	)
	(segment
		(start 187.462922 -16.551148)
		(end 187.461906 -16.550132)
		(width 0.3556)
		(layer "F.Cu")
		(net "GND")
	)
	(segment
		(start 386.364734 -230.622602)
		(end 385.894834 -230.900478)
		(width 0.254)
		(layer "F.Cu")
		(net "GND")
	)
	(segment
		(start 452.016114 -279.766776)
		(end 450.911214 -279.766776)
		(width 0.381)
		(layer "F.Cu")
		(net "GND")
	)
	(segment
		(start 107.051348 -269.661894)
		(end 107.051348 -270.19758)
		(width 0.254)
		(layer "F.Cu")
		(net "GND")
	)
	(segment
		(start 137.594594 -281.869896)
		(end 137.594594 -282.405836)
		(width 0.254)
		(layer "F.Cu")
		(net "GND")
	)
	(segment
		(start 463.659982 -308.666642)
		(end 462.555082 -308.666642)
		(width 0.381)
		(layer "F.Cu")
		(net "GND")
	)
	(segment
		(start 127.69596 -99.68484)
		(end 126.382272 -100.998528)
		(width 0.254)
		(layer "F.Cu")
		(net "GND")
	)
	(segment
		(start 278.711914 -233.016806)
		(end 279.816814 -233.016806)
		(width 0.381)
		(layer "F.Cu")
		(net "GND")
	)
	(segment
		(start 12.240514 -286.56661)
		(end 13.345414 -286.56661)
		(width 0.381)
		(layer "F.Cu")
		(net "GND")
	)
	(segment
		(start 118.79961 -335.541112)
		(end 118.485666 -335.855056)
		(width 0.1778)
		(layer "F.Cu")
		(net "GND")
	)
	(segment
		(start 356.76078 -231.436418)
		(end 356.761034 -231.436164)
		(width 0.2032)
		(layer "F.Cu")
		(net "GND")
	)
	(segment
		(start 441.028582 -271.266666)
		(end 442.133482 -271.266666)
		(width 0.381)
		(layer "F.Cu")
		(net "GND")
	)
	(segment
		(start 432.379882 -196.466714)
		(end 433.484782 -196.466714)
		(width 0.381)
		(layer "F.Cu")
		(net "GND")
	)
	(segment
		(start 186.649614 -232.166668)
		(end 185.544714 -232.166668)
		(width 0.381)
		(layer "F.Cu")
		(net "GND")
	)
	(segment
		(start 23.228046 -242.3668)
		(end 24.332946 -242.3668)
		(width 0.381)
		(layer "F.Cu")
		(net "GND")
	)
	(segment
		(start 94.318582 -335.541112)
		(end 94.318328 -335.540858)
		(width 0.1778)
		(layer "F.Cu")
		(net "GND")
	)
	(segment
		(start 118.328694 -281.05608)
		(end 118.328694 -281.59202)
		(width 0.254)
		(layer "F.Cu")
		(net "GND")
	)
	(segment
		(start 158.813246 -276.366732)
		(end 157.708346 -276.366732)
		(width 0.381)
		(layer "F.Cu")
		(net "GND")
	)
	(segment
		(start 89.555066 -220.855794)
		(end 89.555066 -220.319854)
		(width 0.2032)
		(layer "F.Cu")
		(net "GND")
	)
	(segment
		(start 126.317248 -284.033468)
		(end 126.316994 -284.033722)
		(width 0.254)
		(layer "F.Cu")
		(net "GND")
	)
	(segment
		(start 170.457114 -245.76659)
		(end 171.562014 -245.76659)
		(width 0.381)
		(layer "F.Cu")
		(net "GND")
	)
	(segment
		(start 416.056318 -173.943518)
		(end 415.22015 -173.943518)
		(width 0.2032)
		(layer "F.Cu")
		(net "GND")
	)
	(segment
		(start 306.570126 -436.149242)
		(end 306.570126 -436.59806)
		(width 0.3556)
		(layer "F.Cu")
		(net "GND")
	)
	(segment
		(start 328.194162 -55.004208)
		(end 328.194162 -55.903114)
		(width 0.2032)
		(layer "F.Cu")
		(net "GND")
	)
	(segment
		(start 59.842146 -250.016772)
		(end 60.947046 -250.016772)
		(width 0.381)
		(layer "F.Cu")
		(net "GND")
	)
	(segment
		(start 282.811982 -269.566644)
		(end 283.916882 -269.566644)
		(width 0.381)
		(layer "F.Cu")
		(net "GND")
	)
	(segment
		(start 29.346906 -11.26998)
		(end 29.346906 -12.37488)
		(width 0.3556)
		(layer "F.Cu")
		(net "GND")
	)
	(segment
		(start 377.076716 -259.081016)
		(end 377.076716 -259.093462)
		(width 0.2032)
		(layer "F.Cu")
		(net "GND")
	)
	(segment
		(start 266.619482 -196.466714)
		(end 267.724382 -196.466714)
		(width 0.381)
		(layer "F.Cu")
		(net "GND")
	)
	(segment
		(start 211.619846 -306.116736)
		(end 210.514946 -306.116736)
		(width 0.381)
		(layer "F.Cu")
		(net "GND")
	)
	(segment
		(start 373.317516 -278.614378)
		(end 373.317516 -279.150064)
		(width 0.254)
		(layer "F.Cu")
		(net "GND")
	)
	(segment
		(start 63.942214 -221.116652)
		(end 65.047114 -221.116652)
		(width 0.381)
		(layer "F.Cu")
		(net "GND")
	)
	(segment
		(start 38.315646 -283.166566)
		(end 37.210746 -283.166566)
		(width 0.381)
		(layer "F.Cu")
		(net "GND")
	)
	(segment
		(start 214.615014 -200.716642)
		(end 215.719914 -200.716642)
		(width 0.381)
		(layer "F.Cu")
		(net "GND")
	)
	(segment
		(start 293.799514 -263.616694)
		(end 292.694614 -263.616694)
		(width 0.381)
		(layer "F.Cu")
		(net "GND")
	)
	(segment
		(start 311.666382 -219.41663)
		(end 312.987182 -219.41663)
		(width 0.381)
		(layer "F.Cu")
		(net "GND")
	)
	(segment
		(start 460.664814 -204.96657)
		(end 459.559914 -204.96657)
		(width 0.381)
		(layer "F.Cu")
		(net "GND")
	)
	(segment
		(start 104.231694 -277.800562)
		(end 104.231694 -278.336248)
		(width 0.2032)
		(layer "F.Cu")
		(net "GND")
	)
	(segment
		(start 286.386016 -363.25048)
		(end 286.058864 -363.25048)
		(width 0.2032)
		(layer "F.Cu")
		(net "GND")
	)
	(segment
		(start 159.840676 -285.667196)
		(end 159.791146 -285.716726)
		(width 0.381)
		(layer "F.Cu")
		(net "GND")
	)
	(segment
		(start 96.133412 -238.76127)
		(end 96.133412 -238.225584)
		(width 0.2032)
		(layer "F.Cu")
		(net "GND")
	)
	(segment
		(start 97.653094 -253.919482)
		(end 97.653348 -253.919736)
		(width 0.2032)
		(layer "F.Cu")
		(net "GND")
	)
	(segment
		(start 289.250882 -316.316614)
		(end 290.355782 -316.316614)
		(width 0.381)
		(layer "F.Cu")
		(net "GND")
	)
	(segment
		(start 26.223214 -241.516662)
		(end 27.328114 -241.516662)
		(width 0.381)
		(layer "F.Cu")
		(net "GND")
	)
	(segment
		(start 185.544714 -250.866656)
		(end 184.439814 -250.866656)
		(width 0.381)
		(layer "F.Cu")
		(net "GND")
	)
	(segment
		(start 175.005746 -197.316598)
		(end 173.900846 -197.316598)
		(width 0.381)
		(layer "F.Cu")
		(net "GND")
	)
	(segment
		(start 300.238414 -225.36658)
		(end 301.343314 -225.36658)
		(width 0.381)
		(layer "F.Cu")
		(net "GND")
	)
	(segment
		(start 413.192214 -295.06672)
		(end 414.297114 -295.06672)
		(width 0.381)
		(layer "F.Cu")
		(net "GND")
	)
	(segment
		(start 88.693498 -180.92039)
		(end 88.851232 -180.762656)
		(width 0.3556)
		(layer "F.Cu")
		(net "GND")
	)
	(segment
		(start 384.764026 -66.704464)
		(end 385.316222 -66.704464)
		(width 0.3556)
		(layer "F.Cu")
		(net "GND")
	)
	(segment
		(start 448.572382 -200.716642)
		(end 447.467482 -200.716642)
		(width 0.381)
		(layer "F.Cu")
		(net "GND")
	)
	(segment
		(start 374.147334 -237.133892)
		(end 374.14708 -237.133638)
		(width 0.254)
		(layer "F.Cu")
		(net "GND")
	)
	(segment
		(start 301.128684 -16.715994)
		(end 301.128684 -15.598394)
		(width 0.3556)
		(layer "F.Cu")
		(net "GND")
	)
	(segment
		(start 349.329248 -338.366354)
		(end 349.329248 -337.856068)
		(width 0.381)
		(layer "F.Cu")
		(net "GND")
	)
	(segment
		(start 345.483434 -239.575086)
		(end 345.483434 -239.0394)
		(width 0.2032)
		(layer "F.Cu")
		(net "GND")
	)
	(segment
		(start 275.268182 -316.316614)
		(end 274.163282 -316.316614)
		(width 0.381)
		(layer "F.Cu")
		(net "GND")
	)
	(segment
		(start 458.455014 -268.71676)
		(end 459.559914 -268.71676)
		(width 0.381)
		(layer "F.Cu")
		(net "GND")
	)
	(segment
		(start 278.711914 -317.166752)
		(end 279.816814 -317.166752)
		(width 0.381)
		(layer "F.Cu")
		(net "GND")
	)
	(segment
		(start 279.816814 -199.01662)
		(end 278.711914 -199.01662)
		(width 0.381)
		(layer "F.Cu")
		(net "GND")
	)
	(segment
		(start 414.297114 -281.466798)
		(end 415.402014 -281.466798)
		(width 0.381)
		(layer "F.Cu")
		(net "GND")
	)
	(segment
		(start 293.645844 -415.00552)
		(end 292.84422 -415.00552)
		(width 0.3556)
		(layer "F.Cu")
		(net "GND")
	)
	(segment
		(start 96.133412 -230.622348)
		(end 96.133412 -230.086662)
		(width 0.2032)
		(layer "F.Cu")
		(net "GND")
	)
	(segment
		(start 311.882282 -316.316614)
		(end 312.987182 -316.316614)
		(width 0.381)
		(layer "F.Cu")
		(net "GND")
	)
	(segment
		(start 176.896014 -310.366664)
		(end 178.000914 -310.366664)
		(width 0.381)
		(layer "F.Cu")
		(net "GND")
	)
	(segment
		(start 452.016114 -216.016586)
		(end 450.911214 -216.016586)
		(width 0.381)
		(layer "F.Cu")
		(net "GND")
	)
	(segment
		(start 11.135614 -297.616626)
		(end 12.240514 -297.616626)
		(width 0.381)
		(layer "F.Cu")
		(net "GND")
	)
	(segment
		(start 445.361822 -8.320024)
		(end 445.361822 -7.20471)
		(width 0.3556)
		(layer "F.Cu")
		(net "GND")
	)
	(segment
		(start 93.783912 -247.178576)
		(end 93.784166 -247.178322)
		(width 0.2032)
		(layer "F.Cu")
		(net "GND")
	)
	(segment
		(start 278.711914 -285.716726)
		(end 279.816814 -285.716726)
		(width 0.381)
		(layer "F.Cu")
		(net "GND")
	)
	(segment
		(start 301.343314 -279.766776)
		(end 302.448214 -279.766776)
		(width 0.381)
		(layer "F.Cu")
		(net "GND")
	)
	(segment
		(start 134.305294 -287.567116)
		(end 134.305294 -288.103056)
		(width 0.254)
		(layer "F.Cu")
		(net "GND")
	)
	(segment
		(start 424.836082 -210.066636)
		(end 425.940982 -210.066636)
		(width 0.381)
		(layer "F.Cu")
		(net "GND")
	)
	(segment
		(start 334.205834 -229.808786)
		(end 334.67548 -230.086662)
		(width 0.2032)
		(layer "F.Cu")
		(net "GND")
	)
	(segment
		(start 353.581716 -283.497782)
		(end 353.581462 -283.498036)
		(width 0.254)
		(layer "F.Cu")
		(net "GND")
	)
	(segment
		(start 122.019822 -110.200948)
		(end 122.019822 -109.070648)
		(width 0.3556)
		(layer "F.Cu")
		(net "GND")
	)
	(segment
		(start 124.327412 -238.76127)
		(end 124.327412 -238.225584)
		(width 0.2032)
		(layer "F.Cu")
		(net "GND")
	)
	(segment
		(start 453.121014 -306.116736)
		(end 452.016114 -306.116736)
		(width 0.381)
		(layer "F.Cu")
		(net "GND")
	)
	(segment
		(start 374.61698 -237.947454)
		(end 374.61698 -237.411768)
		(width 0.254)
		(layer "F.Cu")
		(net "GND")
	)
	(segment
		(start 340.894162 -255.547368)
		(end 340.894416 -255.547622)
		(width 0.2032)
		(layer "F.Cu")
		(net "GND")
	)
	(segment
		(start 441.028582 -241.516662)
		(end 442.133482 -241.516662)
		(width 0.381)
		(layer "F.Cu")
		(net "GND")
	)
	(segment
		(start 386.364734 -245.27256)
		(end 387.169152 -245.27256)
		(width 0.2032)
		(layer "F.Cu")
		(net "GND")
	)
	(segment
		(start 118.798848 -281.869896)
		(end 118.798594 -281.87015)
		(width 0.254)
		(layer "F.Cu")
		(net "GND")
	)
	(segment
		(start 420.7637 -165.883844)
		(end 420.548308 -166.099236)
		(width 0.381)
		(layer "F.Cu")
		(net "GND")
	)
	(segment
		(start 93.784166 -220.041724)
		(end 93.784166 -219.506038)
		(width 0.254)
		(layer "F.Cu")
		(net "GND")
	)
	(segment
		(start 122.087894 -277.800562)
		(end 122.087894 -278.336502)
		(width 0.2032)
		(layer "F.Cu")
		(net "GND")
	)
	(segment
		(start 349.24238 -223.297496)
		(end 349.24238 -222.76181)
		(width 0.254)
		(layer "F.Cu")
		(net "GND")
	)
	(segment
		(start 448.572382 -286.56661)
		(end 447.467482 -286.56661)
		(width 0.381)
		(layer "F.Cu")
		(net "GND")
	)
	(segment
		(start 211.619846 -221.96679)
		(end 212.724746 -221.96679)
		(width 0.381)
		(layer "F.Cu")
		(net "GND")
	)
	(segment
		(start 418.397182 -266.1666)
		(end 417.292282 -266.1666)
		(width 0.381)
		(layer "F.Cu")
		(net "GND")
	)
	(segment
		(start 406.753314 -281.466798)
		(end 407.858214 -281.466798)
		(width 0.381)
		(layer "F.Cu")
		(net "GND")
	)
	(segment
		(start 261.285482 -264.466578)
		(end 260.180582 -264.466578)
		(width 0.381)
		(layer "F.Cu")
		(net "GND")
	)
	(segment
		(start 148.19122 -38.971728)
		(end 148.91258 -39.693088)
		(width 0.3556)
		(layer "F.Cu")
		(net "GND")
	)
	(segment
		(start 129.496312 -226.017582)
		(end 129.496566 -226.017328)
		(width 0.254)
		(layer "F.Cu")
		(net "GND")
	)
	(segment
		(start 126.47295 -339.683344)
		(end 126.153672 -340.002622)
		(width 0.254)
		(layer "F.Cu")
		(net "GND")
	)
	(segment
		(start 432.379882 -303.566576)
		(end 433.484782 -303.566576)
		(width 0.381)
		(layer "F.Cu")
		(net "GND")
	)
	(segment
		(start 378.956316 -260.708902)
		(end 378.956316 -261.244588)
		(width 0.2032)
		(layer "F.Cu")
		(net "GND")
	)
	(segment
		(start 108.45673 -59.070748)
		(end 109.06633 -59.070748)
		(width 0.3556)
		(layer "F.Cu")
		(net "GND")
	)
	(segment
		(start 276.373082 -232.166668)
		(end 275.268182 -232.166668)
		(width 0.381)
		(layer "F.Cu")
		(net "GND")
	)
	(segment
		(start 428.279814 -260.21665)
		(end 429.384714 -260.21665)
		(width 0.381)
		(layer "F.Cu")
		(net "GND")
	)
	(segment
		(start 285.150814 -221.96679)
		(end 286.255714 -221.96679)
		(width 0.381)
		(layer "F.Cu")
		(net "GND")
	)
	(segment
		(start 43.520614 -207.51673)
		(end 42.415714 -207.51673)
		(width 0.381)
		(layer "F.Cu")
		(net "GND")
	)
	(segment
		(start 414.297114 -272.116804)
		(end 415.402014 -272.116804)
		(width 0.381)
		(layer "F.Cu")
		(net "GND")
	)
	(segment
		(start 118.328694 -269.66164)
		(end 118.328948 -270.167862)
		(width 0.254)
		(layer "F.Cu")
		(net "GND")
	)
	(segment
		(start 179.12588 -130.666998)
		(end 179.12588 -131.280408)
		(width 0.3556)
		(layer "F.Cu")
		(net "GND")
	)
	(segment
		(start 94.723712 -234.69219)
		(end 94.723712 -234.15625)
		(width 0.2032)
		(layer "F.Cu")
		(net "GND")
	)
	(segment
		(start 130.436112 -220.041978)
		(end 130.436112 -219.506292)
		(width 0.254)
		(layer "F.Cu")
		(net "GND")
	)
	(segment
		(start 293.799514 -298.466764)
		(end 294.904414 -298.466764)
		(width 0.381)
		(layer "F.Cu")
		(net "GND")
	)
	(segment
		(start 424.836082 -196.466714)
		(end 425.940982 -196.466714)
		(width 0.381)
		(layer "F.Cu")
		(net "GND")
	)
	(segment
		(start 281.707082 -272.966688)
		(end 282.811982 -272.966688)
		(width 0.381)
		(layer "F.Cu")
		(net "GND")
	)
	(segment
		(start 89.664794 -270.475456)
		(end 89.664794 -271.011396)
		(width 0.2032)
		(layer "F.Cu")
		(net "GND")
	)
	(segment
		(start 45.859446 -217.716608)
		(end 46.964346 -217.716608)
		(width 0.381)
		(layer "F.Cu")
		(net "GND")
	)
	(segment
		(start 14.579346 -289.11677)
		(end 15.684246 -289.11677)
		(width 0.381)
		(layer "F.Cu")
		(net "GND")
	)
	(segment
		(start 362.869734 -215.972644)
		(end 362.86948 -215.97239)
		(width 0.2032)
		(layer "F.Cu")
		(net "GND")
	)
	(segment
		(start 373.67718 -239.57534)
		(end 373.677434 -239.575086)
		(width 0.2032)
		(layer "F.Cu")
		(net "GND")
	)
	(segment
		(start 281.707082 -245.76659)
		(end 282.811982 -245.76659)
		(width 0.381)
		(layer "F.Cu")
		(net "GND")
	)
	(segment
		(start 427.045882 -211.766658)
		(end 425.940982 -211.766658)
		(width 0.381)
		(layer "F.Cu")
		(net "GND")
	)
	(segment
		(start 132.425694 -276.172676)
		(end 132.425694 -276.708616)
		(width 0.2032)
		(layer "F.Cu")
		(net "GND")
	)
	(segment
		(start 384.485134 -250.155964)
		(end 384.485134 -249.620024)
		(width 0.254)
		(layer "F.Cu")
		(net "GND")
	)
	(segment
		(start 190.093346 -290.816792)
		(end 188.988446 -290.816792)
		(width 0.381)
		(layer "F.Cu")
		(net "GND")
	)
	(segment
		(start 463.659982 -261.066788)
		(end 464.764882 -261.066788)
		(width 0.381)
		(layer "F.Cu")
		(net "GND")
	)
	(segment
		(start 97.183448 -283.497782)
		(end 97.183448 -284.033468)
		(width 0.254)
		(layer "F.Cu")
		(net "GND")
	)
	(segment
		(start 115.979448 -273.730974)
		(end 115.979448 -274.266914)
		(width 0.254)
		(layer "F.Cu")
		(net "GND")
	)
	(segment
		(start 158.813246 -233.016806)
		(end 159.918146 -233.016806)
		(width 0.381)
		(layer "F.Cu")
		(net "GND")
	)
	(segment
		(start 260.180582 -222.816674)
		(end 259.075682 -222.816674)
		(width 0.381)
		(layer "F.Cu")
		(net "GND")
	)
	(segment
		(start 382.715516 -288.381186)
		(end 382.74244 -288.40811)
		(width 0.254)
		(layer "F.Cu")
		(net "GND")
	)
	(segment
		(start 305.443382 -297.616626)
		(end 306.548282 -297.616626)
		(width 0.381)
		(layer "F.Cu")
		(net "GND")
	)
	(segment
		(start 422.945814 -283.166566)
		(end 421.840914 -283.166566)
		(width 0.381)
		(layer "F.Cu")
		(net "GND")
	)
	(segment
		(start 455.986642 -381.094488)
		(end 456.216258 -380.864872)
		(width 0.381)
		(layer "F.Cu")
		(net "GND")
	)
	(segment
		(start 256.080514 -289.11677)
		(end 257.185414 -289.11677)
		(width 0.381)
		(layer "F.Cu")
		(net "GND")
	)
	(segment
		(start 411.958282 -314.616592)
		(end 410.853382 -314.616592)
		(width 0.381)
		(layer "F.Cu")
		(net "GND")
	)
	(segment
		(start 179.105814 -219.41663)
		(end 178.000914 -219.41663)
		(width 0.381)
		(layer "F.Cu")
		(net "GND")
	)
	(segment
		(start 312.987182 -232.166668)
		(end 314.092082 -232.166668)
		(width 0.381)
		(layer "F.Cu")
		(net "GND")
	)
	(segment
		(start 215.719914 -299.316648)
		(end 216.824814 -299.316648)
		(width 0.381)
		(layer "F.Cu")
		(net "GND")
	)
	(segment
		(start 8.140446 -204.96657)
		(end 9.245346 -204.96657)
		(width 0.381)
		(layer "F.Cu")
		(net "GND")
	)
	(segment
		(start 371.327934 -230.622602)
		(end 371.327934 -230.086916)
		(width 0.254)
		(layer "F.Cu")
		(net "GND")
	)
	(segment
		(start 90.134694 -282.683966)
		(end 90.134694 -283.219906)
		(width 0.2032)
		(layer "F.Cu")
		(net "GND")
	)
	(segment
		(start 211.619846 -204.96657)
		(end 212.724746 -204.96657)
		(width 0.381)
		(layer "F.Cu")
		(net "GND")
	)
	(segment
		(start 111.17072 -218.692222)
		(end 111.17072 -218.691968)
		(width 0.2032)
		(layer "F.Cu")
		(net "GND")
	)
	(segment
		(start 13.345414 -235.566712)
		(end 12.240514 -235.566712)
		(width 0.381)
		(layer "F.Cu")
		(net "GND")
	)
	(segment
		(start 181.444646 -206.666592)
		(end 182.549546 -206.666592)
		(width 0.381)
		(layer "F.Cu")
		(net "GND")
	)
	(segment
		(start 11.135614 -299.316648)
		(end 12.240514 -299.316648)
		(width 0.381)
		(layer "F.Cu")
		(net "GND")
	)
	(segment
		(start 207.071214 -194.766692)
		(end 208.176114 -194.766692)
		(width 0.381)
		(layer "F.Cu")
		(net "GND")
	)
	(segment
		(start 290.065968 -411.696154)
		(end 289.405568 -411.696154)
		(width 0.3556)
		(layer "F.Cu")
		(net "GND")
	)
	(segment
		(start 108.820712 -222.76181)
		(end 108.820966 -222.761556)
		(width 0.254)
		(layer "F.Cu")
		(net "GND")
	)
	(segment
		(start 336.555334 -240.389156)
		(end 336.55508 -240.388902)
		(width 0.2032)
		(layer "F.Cu")
		(net "GND")
	)
	(segment
		(start 369.91798 -216.78646)
		(end 369.91798 -216.250774)
		(width 0.254)
		(layer "F.Cu")
		(net "GND")
	)
	(segment
		(start 304.122582 -238.116618)
		(end 305.443382 -238.116618)
		(width 0.381)
		(layer "F.Cu")
		(net "GND")
	)
	(segment
		(start 441.028582 -207.51673)
		(end 442.133482 -207.51673)
		(width 0.381)
		(layer "F.Cu")
		(net "GND")
	)
	(segment
		(start 105.641394 -270.47571)
		(end 105.641394 -271.011396)
		(width 0.254)
		(layer "F.Cu")
		(net "GND")
	)
	(segment
		(start 196.532246 -250.016772)
		(end 197.637146 -250.016772)
		(width 0.381)
		(layer "F.Cu")
		(net "GND")
	)
	(segment
		(start 59.842146 -272.116804)
		(end 60.947046 -272.116804)
		(width 0.381)
		(layer "F.Cu")
		(net "GND")
	)
	(segment
		(start 192.834768 -69.92366)
		(end 193.350642 -69.92366)
		(width 0.254)
		(layer "F.Cu")
		(net "GND")
	)
	(segment
		(start 124.327666 -246.900446)
		(end 124.327412 -246.900192)
		(width 0.2032)
		(layer "F.Cu")
		(net "GND")
	)
	(segment
		(start 342.304116 -283.497782)
		(end 342.304116 -284.033468)
		(width 0.254)
		(layer "F.Cu")
		(net "GND")
	)
	(segment
		(start 162.913314 -284.866588)
		(end 161.808414 -284.866588)
		(width 0.381)
		(layer "F.Cu")
		(net "GND")
	)
	(segment
		(start 98.013012 -232.250234)
		(end 98.013012 -231.714548)
		(width 0.2032)
		(layer "F.Cu")
		(net "GND")
	)
	(segment
		(start 347.876622 -37.455348)
		(end 347.876622 -37.758878)
		(width 0.2032)
		(layer "F.Cu")
		(net "GND")
	)
	(segment
		(start 159.918146 -276.366732)
		(end 158.813246 -276.366732)
		(width 0.381)
		(layer "F.Cu")
		(net "GND")
	)
	(segment
		(start 452.016114 -244.916706)
		(end 450.911214 -244.916706)
		(width 0.381)
		(layer "F.Cu")
		(net "GND")
	)
	(segment
		(start 373.67718 -229.808786)
		(end 373.677434 -229.808532)
		(width 0.2032)
		(layer "F.Cu")
		(net "GND")
	)
	(segment
		(start 44.754546 -300.166786)
		(end 45.859446 -300.166786)
		(width 0.381)
		(layer "F.Cu")
		(net "GND")
	)
	(segment
		(start 178.614832 -355.723952)
		(end 178.95951 -355.379274)
		(width 0.2032)
		(layer "F.Cu")
		(net "GND")
	)
	(segment
		(start 88.615012 -245.272306)
		(end 88.615012 -244.73662)
		(width 0.2032)
		(layer "F.Cu")
		(net "GND")
	)
	(segment
		(start 409.748482 -305.266598)
		(end 410.853382 -305.266598)
		(width 0.381)
		(layer "F.Cu")
		(net "GND")
	)
	(segment
		(start 188.988446 -246.616728)
		(end 187.883546 -246.616728)
		(width 0.381)
		(layer "F.Cu")
		(net "GND")
	)
	(segment
		(start 410.853382 -284.866588)
		(end 411.958282 -284.866588)
		(width 0.381)
		(layer "F.Cu")
		(net "GND")
	)
	(segment
		(start 339.374734 -228.45903)
		(end 339.374734 -228.99497)
		(width 0.2032)
		(layer "F.Cu")
		(net "GND")
	)
	(segment
		(start 329.980798 -50.329846)
		(end 329.980036 -50.329846)
		(width 0.2032)
		(layer "F.Cu")
		(net "GND")
	)
	(segment
		(start 361.460034 -234.691936)
		(end 361.460034 -234.15625)
		(width 0.2032)
		(layer "F.Cu")
		(net "GND")
	)
	(segment
		(start 204.076046 -289.11677)
		(end 205.180946 -289.11677)
		(width 0.381)
		(layer "F.Cu")
		(net "GND")
	)
	(segment
		(start 281.707082 -310.366664)
		(end 282.811982 -310.366664)
		(width 0.381)
		(layer "F.Cu")
		(net "GND")
	)
	(segment
		(start 377.546362 -263.150604)
		(end 377.546362 -263.686544)
		(width 0.2032)
		(layer "F.Cu")
		(net "GND")
	)
	(segment
		(start 359.110534 -238.761524)
		(end 359.11028 -238.76127)
		(width 0.254)
		(layer "F.Cu")
		(net "GND")
	)
	(segment
		(start 301.343314 -313.766708)
		(end 302.664114 -313.766708)
		(width 0.381)
		(layer "F.Cu")
		(net "GND")
	)
	(segment
		(start 39.420546 -263.616694)
		(end 38.315646 -263.616694)
		(width 0.381)
		(layer "F.Cu")
		(net "GND")
	)
	(segment
		(start 176.896014 -299.316648)
		(end 178.000914 -299.316648)
		(width 0.381)
		(layer "F.Cu")
		(net "GND")
	)
	(segment
		(start 123.2281 -412.735268)
		(end 123.38304 -412.735268)
		(width 0.508)
		(layer "F.Cu")
		(net "GND")
	)
	(segment
		(start 406.753314 -265.316716)
		(end 407.858214 -265.316716)
		(width 0.381)
		(layer "F.Cu")
		(net "GND")
	)
	(segment
		(start 372.377716 -259.093462)
		(end 372.377462 -259.616956)
		(width 0.2032)
		(layer "F.Cu")
		(net "GND")
	)
	(segment
		(start 99.422712 -229.808786)
		(end 99.422966 -229.808532)
		(width 0.2032)
		(layer "F.Cu")
		(net "GND")
	)
	(segment
		(start 266.619482 -288.266632)
		(end 267.724382 -288.266632)
		(width 0.381)
		(layer "F.Cu")
		(net "GND")
	)
	(segment
		(start 352.06178 -226.017582)
		(end 352.062034 -226.017328)
		(width 0.254)
		(layer "F.Cu")
		(net "GND")
	)
	(segment
		(start 312.987182 -291.666676)
		(end 314.092082 -291.666676)
		(width 0.381)
		(layer "F.Cu")
		(net "GND")
	)
	(segment
		(start 23.228046 -283.166566)
		(end 24.332946 -283.166566)
		(width 0.381)
		(layer "F.Cu")
		(net "GND")
	)
	(segment
		(start 339.623908 -52.49545)
		(end 339.748876 -52.620418)
		(width 0.2032)
		(layer "F.Cu")
		(net "GND")
	)
	(segment
		(start 346.063316 -275.894546)
		(end 346.063062 -275.8948)
		(width 0.2032)
		(layer "F.Cu")
		(net "GND")
	)
	(segment
		(start 208.176114 -282.316682)
		(end 209.281014 -282.316682)
		(width 0.381)
		(layer "F.Cu")
		(net "GND")
	)
	(segment
		(start 34.871914 -241.516662)
		(end 35.976814 -241.516662)
		(width 0.381)
		(layer "F.Cu")
		(net "GND")
	)
	(segment
		(start 441.028582 -299.316648)
		(end 442.133482 -299.316648)
		(width 0.381)
		(layer "F.Cu")
		(net "GND")
	)
	(segment
		(start 207.071214 -294.216582)
		(end 208.176114 -294.216582)
		(width 0.381)
		(layer "F.Cu")
		(net "GND")
	)
	(segment
		(start 334.05064 -53.619146)
		(end 334.864456 -54.089046)
		(width 0.2032)
		(layer "F.Cu")
		(net "GND")
	)
	(segment
		(start 372.847616 -282.68422)
		(end 372.847616 -283.219906)
		(width 0.254)
		(layer "F.Cu")
		(net "GND")
	)
	(segment
		(start 97.543366 -229.808532)
		(end 97.543366 -229.272846)
		(width 0.2032)
		(layer "F.Cu")
		(net "GND")
	)
	(segment
		(start 65.047114 -241.516662)
		(end 66.152014 -241.516662)
		(width 0.381)
		(layer "F.Cu")
		(net "GND")
	)
	(segment
		(start 275.268182 -277.216616)
		(end 274.163282 -277.216616)
		(width 0.381)
		(layer "F.Cu")
		(net "GND")
	)
	(segment
		(start 432.379882 -288.266632)
		(end 433.484782 -288.266632)
		(width 0.381)
		(layer "F.Cu")
		(net "GND")
	)
	(segment
		(start 138.894312 -221.669864)
		(end 138.894566 -221.133924)
		(width 0.254)
		(layer "F.Cu")
		(net "GND")
	)
	(segment
		(start 362.979716 -279.150064)
		(end 362.979462 -279.150318)
		(width 0.254)
		(layer "F.Cu")
		(net "GND")
	)
	(segment
		(start 65.047114 -286.56661)
		(end 66.152014 -286.56661)
		(width 0.381)
		(layer "F.Cu")
		(net "GND")
	)
	(segment
		(start 409.748482 -245.76659)
		(end 410.853382 -245.76659)
		(width 0.381)
		(layer "F.Cu")
		(net "GND")
	)
	(segment
		(start 349.352362 -271.289272)
		(end 349.352616 -271.289526)
		(width 0.2032)
		(layer "F.Cu")
		(net "GND")
	)
	(segment
		(start 130.414776 -119.425974)
		(end 130.414776 -120.213374)
		(width 0.3556)
		(layer "F.Cu")
		(net "GND")
	)
	(segment
		(start 462.555082 -213.46668)
		(end 463.659982 -213.46668)
		(width 0.381)
		(layer "F.Cu")
		(net "GND")
	)
	(segment
		(start 329.437746 -53.149246)
		(end 329.980036 -53.149246)
		(width 0.381)
		(layer "F.Cu")
		(net "GND")
	)
	(segment
		(start 125.267466 -220.855794)
		(end 125.267466 -220.319854)
		(width 0.2032)
		(layer "F.Cu")
		(net "GND")
	)
	(segment
		(start 14.579346 -306.116736)
		(end 15.684246 -306.116736)
		(width 0.381)
		(layer "F.Cu")
		(net "GND")
	)
	(segment
		(start 448.572382 -207.51673)
		(end 447.467482 -207.51673)
		(width 0.381)
		(layer "F.Cu")
		(net "GND")
	)
	(segment
		(start 49.959514 -221.116652)
		(end 51.064414 -221.116652)
		(width 0.381)
		(layer "F.Cu")
		(net "GND")
	)
	(segment
		(start 35.976814 -272.966688)
		(end 34.871914 -272.966688)
		(width 0.381)
		(layer "F.Cu")
		(net "GND")
	)
	(segment
		(start 27.328114 -205.816708)
		(end 28.433014 -205.816708)
		(width 0.381)
		(layer "F.Cu")
		(net "GND")
	)
	(segment
		(start 340.562946 -42.341546)
		(end 340.290658 -41.871646)
		(width 0.254)
		(layer "F.Cu")
		(net "GND")
	)
	(segment
		(start 121.978166 -220.041724)
		(end 121.978166 -219.506038)
		(width 0.254)
		(layer "F.Cu")
		(net "GND")
	)
	(segment
		(start 190.093346 -300.166786)
		(end 188.988446 -300.166786)
		(width 0.381)
		(layer "F.Cu")
		(net "GND")
	)
	(segment
		(start 332.796134 -222.48368)
		(end 332.32598 -222.761556)
		(width 0.2032)
		(layer "F.Cu")
		(net "GND")
	)
	(segment
		(start 8.140446 -242.3668)
		(end 9.245346 -242.3668)
		(width 0.381)
		(layer "F.Cu")
		(net "GND")
	)
	(segment
		(start 29.666946 -270.416782)
		(end 30.771846 -270.416782)
		(width 0.381)
		(layer "F.Cu")
		(net "GND")
	)
	(segment
		(start 95.303848 -272.639028)
		(end 95.303594 -272.639282)
		(width 0.2032)
		(layer "F.Cu")
		(net "GND")
	)
	(segment
		(start 328.242422 -36.617148)
		(end 328.242422 -36.363148)
		(width 0.2032)
		(layer "F.Cu")
		(net "GND")
	)
	(segment
		(start 276.373082 -205.816708)
		(end 275.268182 -205.816708)
		(width 0.381)
		(layer "F.Cu")
		(net "GND")
	)
	(segment
		(start 118.798848 -273.730974)
		(end 118.798594 -274.266914)
		(width 0.254)
		(layer "F.Cu")
		(net "GND")
	)
	(segment
		(start 27.328114 -264.466578)
		(end 28.433014 -264.466578)
		(width 0.381)
		(layer "F.Cu")
		(net "GND")
	)
	(segment
		(start 98.122994 -265.592306)
		(end 98.123248 -265.592306)
		(width 0.254)
		(layer "F.Cu")
		(net "GND")
	)
	(segment
		(start 338.434934 -230.086916)
		(end 338.43468 -230.086662)
		(width 0.254)
		(layer "F.Cu")
		(net "GND")
	)
	(segment
		(start 124.437648 -286.7533)
		(end 124.437648 -287.288986)
		(width 0.254)
		(layer "F.Cu")
		(net "GND")
	)
	(segment
		(start 130.436112 -216.78646)
		(end 130.436112 -216.250774)
		(width 0.254)
		(layer "F.Cu")
		(net "GND")
	)
	(segment
		(start 381.305562 -274.54479)
		(end 381.305562 -275.08073)
		(width 0.2032)
		(layer "F.Cu")
		(net "GND")
	)
	(segment
		(start 178.000914 -305.266598)
		(end 179.105814 -305.266598)
		(width 0.381)
		(layer "F.Cu")
		(net "GND")
	)
	(segment
		(start 104.701848 -286.7533)
		(end 104.701848 -287.28924)
		(width 0.254)
		(layer "F.Cu")
		(net "GND")
	)
	(segment
		(start 383.545334 -231.714548)
		(end 383.545334 -232.250488)
		(width 0.254)
		(layer "F.Cu")
		(net "GND")
	)
	(segment
		(start 380.835916 -266.127992)
		(end 380.835662 -266.128246)
		(width 0.254)
		(layer "F.Cu")
		(net "GND")
	)
	(segment
		(start 8.140446 -289.11677)
		(end 9.245346 -289.11677)
		(width 0.381)
		(layer "F.Cu")
		(net "GND")
	)
	(segment
		(start 164.99205 -24.263858)
		(end 165.646862 -24.91867)
		(width 0.3556)
		(layer "F.Cu")
		(net "GND")
	)
	(segment
		(start 378.846334 -237.133892)
		(end 378.84608 -237.133638)
		(width 0.254)
		(layer "F.Cu")
		(net "GND")
	)
	(segment
		(start 349.712534 -246.36476)
		(end 349.71228 -246.364506)
		(width 0.2032)
		(layer "F.Cu")
		(net "GND")
	)
	(segment
		(start 342.735154 -53.618892)
		(end 343.006934 -54.088792)
		(width 0.2032)
		(layer "F.Cu")
		(net "GND")
	)
	(segment
		(start 254.975614 -301.866808)
		(end 256.080514 -301.866808)
		(width 0.381)
		(layer "F.Cu")
		(net "GND")
	)
	(segment
		(start 96.243648 -278.614378)
		(end 96.243648 -279.150064)
		(width 0.254)
		(layer "F.Cu")
		(net "GND")
	)
	(segment
		(start 282.811982 -266.1666)
		(end 283.916882 -266.1666)
		(width 0.381)
		(layer "F.Cu")
		(net "GND")
	)
	(segment
		(start 120.208294 -271.289272)
		(end 120.208548 -271.825212)
		(width 0.2032)
		(layer "F.Cu")
		(net "GND")
	)
	(segment
		(start 207.071214 -241.516662)
		(end 208.176114 -241.516662)
		(width 0.381)
		(layer "F.Cu")
		(net "GND")
	)
	(segment
		(start 334.864456 -43.751246)
		(end 334.324198 -43.751246)
		(width 0.2032)
		(layer "F.Cu")
		(net "GND")
	)
	(segment
		(start 275.268182 -310.366664)
		(end 274.163282 -310.366664)
		(width 0.381)
		(layer "F.Cu")
		(net "GND")
	)
	(segment
		(start 48.854614 -303.566576)
		(end 49.959514 -303.566576)
		(width 0.381)
		(layer "F.Cu")
		(net "GND")
	)
	(segment
		(start 162.913314 -295.916604)
		(end 164.018214 -295.916604)
		(width 0.381)
		(layer "F.Cu")
		(net "GND")
	)
	(segment
		(start 414.297114 -233.016806)
		(end 415.402014 -233.016806)
		(width 0.381)
		(layer "F.Cu")
		(net "GND")
	)
	(segment
		(start 286.255714 -307.816758)
		(end 287.360614 -307.816758)
		(width 0.381)
		(layer "F.Cu")
		(net "GND")
	)
	(segment
		(start 262.519414 -270.416782)
		(end 263.624314 -270.416782)
		(width 0.381)
		(layer "F.Cu")
		(net "GND")
	)
	(segment
		(start 463.659982 -284.866588)
		(end 462.555082 -284.866588)
		(width 0.381)
		(layer "F.Cu")
		(net "GND")
	)
	(segment
		(start 304.1396 -61.130688)
		(end 303.48936 -61.130688)
		(width 0.3556)
		(layer "F.Cu")
		(net "GND")
	)
	(segment
		(start 180.339746 -250.016772)
		(end 181.444646 -250.016772)
		(width 0.381)
		(layer "F.Cu")
		(net "GND")
	)
	(segment
		(start 296.794682 -316.316614)
		(end 297.899582 -316.316614)
		(width 0.381)
		(layer "F.Cu")
		(net "GND")
	)
	(segment
		(start 109.744764 -13.974064)
		(end 110.556548 -13.974064)
		(width 0.3556)
		(layer "F.Cu")
		(net "GND")
	)
	(segment
		(start 370.967762 -277.800562)
		(end 370.968016 -278.336502)
		(width 0.254)
		(layer "F.Cu")
		(net "GND")
	)
	(segment
		(start 428.279814 -278.066754)
		(end 429.384714 -278.066754)
		(width 0.381)
		(layer "F.Cu")
		(net "GND")
	)
	(segment
		(start 364.859316 -263.96442)
		(end 364.859316 -264.499852)
		(width 0.2032)
		(layer "F.Cu")
		(net "GND")
	)
	(segment
		(start 13.6398 -426.15485)
		(end 12.9286 -426.15485)
		(width 0.3556)
		(layer "F.Cu")
		(net "GND")
	)
	(segment
		(start 425.940982 -232.166668)
		(end 427.045882 -232.166668)
		(width 0.381)
		(layer "F.Cu")
		(net "GND")
	)
	(segment
		(start 127.616712 -229.808786)
		(end 127.616966 -229.808532)
		(width 0.2032)
		(layer "F.Cu")
		(net "GND")
	)
	(segment
		(start 413.192214 -197.316598)
		(end 414.297114 -197.316598)
		(width 0.381)
		(layer "F.Cu")
		(net "GND")
	)
	(segment
		(start 365.799116 -275.35886)
		(end 365.798862 -275.8948)
		(width 0.254)
		(layer "F.Cu")
		(net "GND")
	)
	(segment
		(start 125.377448 -262.336534)
		(end 125.377448 -262.872474)
		(width 0.2032)
		(layer "F.Cu")
		(net "GND")
	)
	(segment
		(start 282.811982 -228.766624)
		(end 283.916882 -228.766624)
		(width 0.381)
		(layer "F.Cu")
		(net "GND")
	)
	(segment
		(start 342.932512 -54.900068)
		(end 343.006934 -55.028592)
		(width 0.2032)
		(layer "F.Cu")
		(net "GND")
	)
	(segment
		(start 441.308236 -102.14102)
		(end 441.308236 -101.34346)
		(width 0.3556)
		(layer "F.Cu")
		(net "GND")
	)
	(segment
		(start 382.245362 -268.033754)
		(end 382.245616 -268.569694)
		(width 0.2032)
		(layer "F.Cu")
		(net "GND")
	)
	(segment
		(start 347.472762 -258.802886)
		(end 347.473016 -258.80314)
		(width 0.2032)
		(layer "F.Cu")
		(net "GND")
	)
	(segment
		(start 347.363034 -229.808532)
		(end 347.363034 -229.272846)
		(width 0.2032)
		(layer "F.Cu")
		(net "GND")
	)
	(segment
		(start 379.426216 -282.68422)
		(end 379.426216 -283.219906)
		(width 0.254)
		(layer "F.Cu")
		(net "GND")
	)
	(segment
		(start 197.637146 -317.166752)
		(end 196.532246 -317.166752)
		(width 0.381)
		(layer "F.Cu")
		(net "GND")
	)
	(segment
		(start 460.664814 -233.016806)
		(end 459.559914 -233.016806)
		(width 0.381)
		(layer "F.Cu")
		(net "GND")
	)
	(segment
		(start 100.362512 -216.78646)
		(end 100.362512 -216.250774)
		(width 0.254)
		(layer "F.Cu")
		(net "GND")
	)
	(segment
		(start 422.72712 -362.168186)
		(end 422.72712 -361.70235)
		(width 0.2032)
		(layer "F.Cu")
		(net "GND")
	)
	(segment
		(start 286.255714 -238.966756)
		(end 287.360614 -238.966756)
		(width 0.381)
		(layer "F.Cu")
		(net "GND")
	)
	(segment
		(start 132.425694 -258.2672)
		(end 132.425694 -258.802886)
		(width 0.2032)
		(layer "F.Cu")
		(net "GND")
	)
	(segment
		(start 372.26748 -242.016788)
		(end 372.26748 -241.481102)
		(width 0.2032)
		(layer "F.Cu")
		(net "GND")
	)
	(segment
		(start 304.338482 -266.1666)
		(end 305.443382 -266.1666)
		(width 0.381)
		(layer "F.Cu")
		(net "GND")
	)
	(segment
		(start 162.913314 -224.516696)
		(end 164.018214 -224.516696)
		(width 0.381)
		(layer "F.Cu")
		(net "GND")
	)
	(segment
		(start 180.339746 -208.366614)
		(end 181.444646 -208.366614)
		(width 0.381)
		(layer "F.Cu")
		(net "GND")
	)
	(segment
		(start 345.143836 -59.682634)
		(end 345.143836 -59.505596)
		(width 0.2032)
		(layer "F.Cu")
		(net "GND")
	)
	(segment
		(start 278.711914 -234.716574)
		(end 279.816814 -234.716574)
		(width 0.381)
		(layer "F.Cu")
		(net "GND")
	)
	(segment
		(start 266.619482 -267.866622)
		(end 267.724382 -267.866622)
		(width 0.381)
		(layer "F.Cu")
		(net "GND")
	)
	(segment
		(start 18.679414 -247.466612)
		(end 19.784314 -247.466612)
		(width 0.381)
		(layer "F.Cu")
		(net "GND")
	)
	(segment
		(start 413.192214 -290.816792)
		(end 414.297114 -290.816792)
		(width 0.381)
		(layer "F.Cu")
		(net "GND")
	)
	(segment
		(start 204.076046 -212.616796)
		(end 205.180946 -212.616796)
		(width 0.381)
		(layer "F.Cu")
		(net "GND")
	)
	(segment
		(start 358.170734 -248.528078)
		(end 358.170734 -247.992138)
		(width 0.254)
		(layer "F.Cu")
		(net "GND")
	)
	(segment
		(start 275.268182 -258.516628)
		(end 274.163282 -258.516628)
		(width 0.381)
		(layer "F.Cu")
		(net "GND")
	)
	(segment
		(start 278.711914 -283.166566)
		(end 279.816814 -283.166566)
		(width 0.381)
		(layer "F.Cu")
		(net "GND")
	)
	(segment
		(start 108.820712 -226.553268)
		(end 108.820712 -226.017582)
		(width 0.254)
		(layer "F.Cu")
		(net "GND")
	)
	(segment
		(start 109.38637 -14.903958)
		(end 109.38637 -14.332458)
		(width 0.3556)
		(layer "F.Cu")
		(net "GND")
	)
	(segment
		(start 243.5479 -251.755148)
		(end 243.72189 -251.581158)
		(width 0.3556)
		(layer "F.Cu")
		(net "GND")
	)
	(segment
		(start 331.880718 -50.799746)
		(end 332.422246 -51.739546)
		(width 0.2032)
		(layer "F.Cu")
		(net "GND")
	)
	(segment
		(start 386.83438 -226.553268)
		(end 387.774434 -226.017328)
		(width 0.254)
		(layer "F.Cu")
		(net "GND")
	)
	(segment
		(start 127.616712 -247.714262)
		(end 127.616966 -247.714008)
		(width 0.2032)
		(layer "F.Cu")
		(net "GND")
	)
	(segment
		(start 190.093346 -248.31675)
		(end 188.988446 -248.31675)
		(width 0.381)
		(layer "F.Cu")
		(net "GND")
	)
	(segment
		(start 208.176114 -215.166702)
		(end 209.281014 -215.166702)
		(width 0.381)
		(layer "F.Cu")
		(net "GND")
	)
	(segment
		(start 260.180582 -250.866656)
		(end 259.075682 -250.866656)
		(width 0.381)
		(layer "F.Cu")
		(net "GND")
	)
	(segment
		(start 445.577214 -223.666558)
		(end 444.472314 -223.666558)
		(width 0.381)
		(layer "F.Cu")
		(net "GND")
	)
	(segment
		(start 13.800582 -408.116786)
		(end 13.800582 -407.507186)
		(width 0.3556)
		(layer "F.Cu")
		(net "GND")
	)
	(segment
		(start 305.443382 -230.466646)
		(end 306.548282 -230.466646)
		(width 0.381)
		(layer "F.Cu")
		(net "GND")
	)
	(segment
		(start 432.379882 -230.466646)
		(end 433.484782 -230.466646)
		(width 0.381)
		(layer "F.Cu")
		(net "GND")
	)
	(segment
		(start 56.398414 -297.616626)
		(end 57.503314 -297.616626)
		(width 0.381)
		(layer "F.Cu")
		(net "GND")
	)
	(segment
		(start 178.000914 -291.666676)
		(end 179.105814 -291.666676)
		(width 0.381)
		(layer "F.Cu")
		(net "GND")
	)
	(segment
		(start 215.719914 -249.166634)
		(end 216.824814 -249.166634)
		(width 0.381)
		(layer "F.Cu")
		(net "GND")
	)
	(segment
		(start 124.797312 -222.76181)
		(end 124.797566 -222.761556)
		(width 0.254)
		(layer "F.Cu")
		(net "GND")
	)
	(segment
		(start 266.619482 -230.466646)
		(end 267.724382 -230.466646)
		(width 0.381)
		(layer "F.Cu")
		(net "GND")
	)
	(segment
		(start 180.339492 -26.240232)
		(end 180.957982 -26.240232)
		(width 0.254)
		(layer "F.Cu")
		(net "GND")
	)
	(segment
		(start 98.482912 -247.714262)
		(end 98.482912 -247.178322)
		(width 0.2032)
		(layer "F.Cu")
		(net "GND")
	)
	(segment
		(start 406.753314 -267.016738)
		(end 407.858214 -267.016738)
		(width 0.381)
		(layer "F.Cu")
		(net "GND")
	)
	(segment
		(start 18.484596 -393.615926)
		(end 18.646902 -393.45362)
		(width 0.254)
		(layer "F.Cu")
		(net "GND")
	)
	(segment
		(start 448.572382 -226.216718)
		(end 447.467482 -226.216718)
		(width 0.381)
		(layer "F.Cu")
		(net "GND")
	)
	(segment
		(start 372.26748 -232.250234)
		(end 372.26748 -231.714548)
		(width 0.254)
		(layer "F.Cu")
		(net "GND")
	)
	(segment
		(start 432.379882 -299.316648)
		(end 433.484782 -299.316648)
		(width 0.381)
		(layer "F.Cu")
		(net "GND")
	)
	(segment
		(start 378.016516 -284.033468)
		(end 378.016262 -284.033722)
		(width 0.254)
		(layer "F.Cu")
		(net "GND")
	)
	(segment
		(start 181.444646 -309.51678)
		(end 182.549546 -309.51678)
		(width 0.381)
		(layer "F.Cu")
		(net "GND")
	)
	(segment
		(start 414.297114 -220.266768)
		(end 415.656014 -220.266768)
		(width 0.381)
		(layer "F.Cu")
		(net "GND")
	)
	(segment
		(start 30.771846 -206.666592)
		(end 31.876746 -206.666592)
		(width 0.381)
		(layer "F.Cu")
		(net "GND")
	)
	(segment
		(start 256.080514 -206.666592)
		(end 257.185414 -206.666592)
		(width 0.381)
		(layer "F.Cu")
		(net "GND")
	)
	(segment
		(start 23.228046 -206.666592)
		(end 24.332946 -206.666592)
		(width 0.381)
		(layer "F.Cu")
		(net "GND")
	)
	(segment
		(start 26.223214 -303.566576)
		(end 27.328114 -303.566576)
		(width 0.381)
		(layer "F.Cu")
		(net "GND")
	)
	(segment
		(start 462.555082 -269.566644)
		(end 463.659982 -269.566644)
		(width 0.381)
		(layer "F.Cu")
		(net "GND")
	)
	(segment
		(start 180.339746 -236.416596)
		(end 181.444646 -236.416596)
		(width 0.381)
		(layer "F.Cu")
		(net "GND")
	)
	(segment
		(start 333.845662 -281.869896)
		(end 333.845662 -282.405836)
		(width 0.2032)
		(layer "F.Cu")
		(net "GND")
	)
	(segment
		(start 346.42298 -223.297496)
		(end 346.42298 -222.76181)
		(width 0.254)
		(layer "F.Cu")
		(net "GND")
	)
	(segment
		(start 340.894162 -279.96388)
		(end 340.894416 -279.964134)
		(width 0.254)
		(layer "F.Cu")
		(net "GND")
	)
	(segment
		(start 122.917712 -234.69219)
		(end 122.917712 -234.15625)
		(width 0.254)
		(layer "F.Cu")
		(net "GND")
	)
	(segment
		(start 377.546362 -256.807462)
		(end 377.546616 -257.175254)
		(width 0.2032)
		(layer "F.Cu")
		(net "GND")
	)
	(segment
		(start 108.351066 -224.111566)
		(end 108.351066 -223.575626)
		(width 0.2032)
		(layer "F.Cu")
		(net "GND")
	)
	(segment
		(start 97.543112 -226.017582)
		(end 97.543366 -226.017328)
		(width 0.254)
		(layer "F.Cu")
		(net "GND")
	)
	(segment
		(start 107.521248 -270.475456)
		(end 107.521248 -271.011142)
		(width 0.2032)
		(layer "F.Cu")
		(net "GND")
	)
	(segment
		(start 188.988446 -270.416782)
		(end 187.883546 -270.416782)
		(width 0.381)
		(layer "F.Cu")
		(net "GND")
	)
	(segment
		(start 57.503314 -211.766658)
		(end 58.608214 -211.766658)
		(width 0.381)
		(layer "F.Cu")
		(net "GND")
	)
	(segment
		(start 344.183716 -286.7533)
		(end 344.183716 -287.288986)
		(width 0.254)
		(layer "F.Cu")
		(net "GND")
	)
	(segment
		(start 383.545334 -226.831144)
		(end 383.545334 -227.367084)
		(width 0.254)
		(layer "F.Cu")
		(net "GND")
	)
	(segment
		(start 48.854614 -205.816708)
		(end 49.959514 -205.816708)
		(width 0.381)
		(layer "F.Cu")
		(net "GND")
	)
	(segment
		(start 373.67718 -241.203226)
		(end 373.67718 -240.667286)
		(width 0.2032)
		(layer "F.Cu")
		(net "GND")
	)
	(segment
		(start 63.942214 -305.266598)
		(end 65.047114 -305.266598)
		(width 0.381)
		(layer "F.Cu")
		(net "GND")
	)
	(segment
		(start 158.813246 -263.616694)
		(end 157.708346 -263.616694)
		(width 0.381)
		(layer "F.Cu")
		(net "GND")
	)
	(segment
		(start 275.268182 -261.066788)
		(end 274.163282 -261.066788)
		(width 0.381)
		(layer "F.Cu")
		(net "GND")
	)
	(segment
		(start 336.195162 -253.383796)
		(end 336.195162 -253.919736)
		(width 0.2032)
		(layer "F.Cu")
		(net "GND")
	)
	(segment
		(start 414.161478 -344.010996)
		(end 415.101786 -344.010996)
		(width 0.508)
		(layer "F.Cu")
		(net "GND")
	)
	(segment
		(start 204.968094 -103.765096)
		(end 204.003148 -103.765096)
		(width 0.3556)
		(layer "F.Cu")
		(net "GND")
	)
	(segment
		(start 93.783912 -223.297496)
		(end 93.783912 -222.76181)
		(width 0.254)
		(layer "F.Cu")
		(net "GND")
	)
	(segment
		(start 308.887114 -295.06672)
		(end 307.782214 -295.06672)
		(width 0.381)
		(layer "F.Cu")
		(net "GND")
	)
	(segment
		(start 169.352214 -232.166668)
		(end 170.457114 -232.166668)
		(width 0.381)
		(layer "F.Cu")
		(net "GND")
	)
	(segment
		(start 180.339746 -246.616728)
		(end 181.444646 -246.616728)
		(width 0.381)
		(layer "F.Cu")
		(net "GND")
	)
	(segment
		(start 125.377448 -283.497782)
		(end 125.377448 -284.033722)
		(width 0.254)
		(layer "F.Cu")
		(net "GND")
	)
	(segment
		(start 115.46332 -417.393628)
		(end 114.78514 -417.393628)
		(width 0.3556)
		(layer "F.Cu")
		(net "GND")
	)
	(segment
		(start 19.784314 -194.766692)
		(end 18.679414 -194.766692)
		(width 0.381)
		(layer "F.Cu")
		(net "GND")
	)
	(segment
		(start 380.725934 -248.528078)
		(end 380.725934 -247.992138)
		(width 0.2032)
		(layer "F.Cu")
		(net "GND")
	)
	(segment
		(start 21.1074 -165.039548)
		(end 20.816062 -165.039548)
		(width 0.3556)
		(layer "F.Cu")
		(net "GND")
	)
	(segment
		(start 293.578788 -58.459878)
		(end 294.175688 -58.459878)
		(width 0.3556)
		(layer "F.Cu")
		(net "GND")
	)
	(segment
		(start 187.883546 -287.416748)
		(end 188.988446 -287.416748)
		(width 0.381)
		(layer "F.Cu")
		(net "GND")
	)
	(segment
		(start 336.195162 -268.033754)
		(end 336.195162 -268.569694)
		(width 0.2032)
		(layer "F.Cu")
		(net "GND")
	)
	(segment
		(start 282.811982 -286.56661)
		(end 283.916882 -286.56661)
		(width 0.381)
		(layer "F.Cu")
		(net "GND")
	)
	(segment
		(start 406.753314 -296.766742)
		(end 407.858214 -296.766742)
		(width 0.381)
		(layer "F.Cu")
		(net "GND")
	)
	(segment
		(start 135.605266 -246.364506)
		(end 136.075166 -246.08663)
		(width 0.254)
		(layer "F.Cu")
		(net "GND")
	)
	(segment
		(start 170.155616 -104.975406)
		(end 169.755566 -104.575356)
		(width 0.3556)
		(layer "F.Cu")
		(net "GND")
	)
	(segment
		(start 195.427346 -197.316598)
		(end 196.532246 -197.316598)
		(width 0.381)
		(layer "F.Cu")
		(net "GND")
	)
	(segment
		(start 452.016114 -251.716794)
		(end 450.911214 -251.716794)
		(width 0.381)
		(layer "F.Cu")
		(net "GND")
	)
	(segment
		(start 361.45978 -229.808786)
		(end 361.460034 -229.808532)
		(width 0.2032)
		(layer "F.Cu")
		(net "GND")
	)
	(segment
		(start 432.379882 -211.766658)
		(end 433.484782 -211.766658)
		(width 0.381)
		(layer "F.Cu")
		(net "GND")
	)
	(segment
		(start 293.799514 -279.766776)
		(end 292.694614 -279.766776)
		(width 0.381)
		(layer "F.Cu")
		(net "GND")
	)
	(segment
		(start 307.642514 -220.266768)
		(end 308.887114 -220.266768)
		(width 0.381)
		(layer "F.Cu")
		(net "GND")
	)
	(segment
		(start 339.014562 -271.289272)
		(end 339.014562 -271.825212)
		(width 0.2032)
		(layer "F.Cu")
		(net "GND")
	)
	(segment
		(start 328.188828 -40.275002)
		(end 328.244962 -40.218868)
		(width 0.2032)
		(layer "F.Cu")
		(net "GND")
	)
	(segment
		(start 358.640634 -229.808786)
		(end 358.640634 -229.272846)
		(width 0.2032)
		(layer "F.Cu")
		(net "GND")
	)
	(segment
		(start 67.812412 -40.437562)
		(end 67.202812 -40.437562)
		(width 0.3556)
		(layer "F.Cu")
		(net "GND")
	)
	(segment
		(start 193.088514 -228.766624)
		(end 191.983614 -228.766624)
		(width 0.381)
		(layer "F.Cu")
		(net "GND")
	)
	(segment
		(start 261.285482 -221.116652)
		(end 260.180582 -221.116652)
		(width 0.381)
		(layer "F.Cu")
		(net "GND")
	)
	(segment
		(start 372.377716 -257.45313)
		(end 372.377462 -257.98907)
		(width 0.2032)
		(layer "F.Cu")
		(net "GND")
	)
	(segment
		(start 107.521248 -265.592306)
		(end 107.521248 -266.127992)
		(width 0.254)
		(layer "F.Cu")
		(net "GND")
	)
	(segment
		(start 42.415714 -222.816674)
		(end 41.310814 -222.816674)
		(width 0.381)
		(layer "F.Cu")
		(net "GND")
	)
	(segment
		(start 211.619846 -233.016806)
		(end 212.724746 -233.016806)
		(width 0.381)
		(layer "F.Cu")
		(net "GND")
	)
	(segment
		(start 346.42298 -216.250774)
		(end 346.423234 -216.25052)
		(width 0.254)
		(layer "F.Cu")
		(net "GND")
	)
	(segment
		(start 65.047114 -213.46668)
		(end 66.152014 -213.46668)
		(width 0.381)
		(layer "F.Cu")
		(net "GND")
	)
	(segment
		(start 185.663078 -16.551148)
		(end 185.662062 -16.550132)
		(width 0.3556)
		(layer "F.Cu")
		(net "GND")
	)
	(segment
		(start 135.714994 -255.825498)
		(end 135.714994 -256.361438)
		(width 0.2032)
		(layer "F.Cu")
		(net "GND")
	)
	(segment
		(start 308.887114 -285.716726)
		(end 307.566314 -285.716726)
		(width 0.381)
		(layer "F.Cu")
		(net "GND")
	)
	(segment
		(start 285.150814 -234.716574)
		(end 286.255714 -234.716574)
		(width 0.381)
		(layer "F.Cu")
		(net "GND")
	)
	(segment
		(start 12.240514 -284.866588)
		(end 13.345414 -284.866588)
		(width 0.381)
		(layer "F.Cu")
		(net "GND")
	)
	(segment
		(start 121.978166 -234.691936)
		(end 121.978166 -234.15625)
		(width 0.254)
		(layer "F.Cu")
		(net "GND")
	)
	(segment
		(start 149.397974 -35.840162)
		(end 149.397974 -37.054282)
		(width 0.3556)
		(layer "F.Cu")
		(net "GND")
	)
	(segment
		(start 433.166774 -8.320024)
		(end 433.166774 -9.424924)
		(width 0.3556)
		(layer "F.Cu")
		(net "GND")
	)
	(segment
		(start 353.94138 -226.017582)
		(end 353.941634 -226.017328)
		(width 0.254)
		(layer "F.Cu")
		(net "GND")
	)
	(segment
		(start 19.784314 -233.86669)
		(end 20.889214 -233.86669)
		(width 0.381)
		(layer "F.Cu")
		(net "GND")
	)
	(segment
		(start 60.947046 -225.36658)
		(end 62.051946 -225.36658)
		(width 0.381)
		(layer "F.Cu")
		(net "GND")
	)
	(segment
		(start 88.725248 -283.497782)
		(end 88.725248 -284.033722)
		(width 0.254)
		(layer "F.Cu")
		(net "GND")
	)
	(segment
		(start 193.088514 -278.916638)
		(end 194.193414 -278.916638)
		(width 0.381)
		(layer "F.Cu")
		(net "GND")
	)
	(segment
		(start 260.180582 -211.766658)
		(end 259.075682 -211.766658)
		(width 0.381)
		(layer "F.Cu")
		(net "GND")
	)
	(segment
		(start 204.076046 -227.066602)
		(end 205.180946 -227.066602)
		(width 0.381)
		(layer "F.Cu")
		(net "GND")
	)
	(segment
		(start 343.005156 -56.908446)
		(end 342.735154 -56.438292)
		(width 0.2032)
		(layer "F.Cu")
		(net "GND")
	)
	(segment
		(start 351.702116 -267.219938)
		(end 351.701862 -267.220192)
		(width 0.254)
		(layer "F.Cu")
		(net "GND")
	)
	(segment
		(start 277.607014 -285.716726)
		(end 278.711914 -285.716726)
		(width 0.381)
		(layer "F.Cu")
		(net "GND")
	)
	(segment
		(start 260.180582 -288.266632)
		(end 259.075682 -288.266632)
		(width 0.381)
		(layer "F.Cu")
		(net "GND")
	)
	(segment
		(start 42.415714 -219.41663)
		(end 41.310814 -219.41663)
		(width 0.381)
		(layer "F.Cu")
		(net "GND")
	)
	(segment
		(start 263.624314 -296.766742)
		(end 264.729214 -296.766742)
		(width 0.381)
		(layer "F.Cu")
		(net "GND")
	)
	(segment
		(start 129.026666 -214.344758)
		(end 129.026666 -213.732618)
		(width 0.254)
		(layer "F.Cu")
		(net "GND")
	)
	(segment
		(start 342.537542 -334.191102)
		(end 342.243918 -334.191102)
		(width 0.2032)
		(layer "F.Cu")
		(net "GND")
	)
	(segment
		(start 100.942394 -266.128246)
		(end 100.942394 -265.592306)
		(width 0.254)
		(layer "F.Cu")
		(net "GND")
	)
	(segment
		(start 463.659982 -272.966688)
		(end 462.555082 -272.966688)
		(width 0.381)
		(layer "F.Cu")
		(net "GND")
	)
	(segment
		(start 380.725934 -217.600276)
		(end 380.725934 -217.064336)
		(width 0.2032)
		(layer "F.Cu")
		(net "GND")
	)
	(segment
		(start 385.424934 -237.133892)
		(end 384.48488 -236.597952)
		(width 0.254)
		(layer "F.Cu")
		(net "GND")
	)
	(segment
		(start 91.904312 -222.76181)
		(end 91.904566 -222.761556)
		(width 0.254)
		(layer "F.Cu")
		(net "GND")
	)
	(segment
		(start 162.913314 -211.766658)
		(end 164.018214 -211.766658)
		(width 0.381)
		(layer "F.Cu")
		(net "GND")
	)
	(segment
		(start 406.753314 -216.016586)
		(end 408.151584 -216.016586)
		(width 0.381)
		(layer "F.Cu")
		(net "GND")
	)
	(segment
		(start 214.615014 -238.116618)
		(end 215.719914 -238.116618)
		(width 0.381)
		(layer "F.Cu")
		(net "GND")
	)
	(segment
		(start 116.339112 -229.808786)
		(end 116.339366 -229.808532)
		(width 0.254)
		(layer "F.Cu")
		(net "GND")
	)
	(segment
		(start 65.047114 -291.666676)
		(end 66.152014 -291.666676)
		(width 0.381)
		(layer "F.Cu")
		(net "GND")
	)
	(segment
		(start 345.483434 -244.45849)
		(end 345.483434 -243.922804)
		(width 0.2032)
		(layer "F.Cu")
		(net "GND")
	)
	(segment
		(start 136.655048 -276.986492)
		(end 136.655048 -277.522178)
		(width 0.254)
		(layer "F.Cu")
		(net "GND")
	)
	(segment
		(start 136.545066 -215.436958)
		(end 136.54532 -215.436704)
		(width 0.254)
		(layer "F.Cu")
		(net "GND")
	)
	(segment
		(start 129.026666 -246.900446)
		(end 129.026666 -246.364506)
		(width 0.2032)
		(layer "F.Cu")
		(net "GND")
	)
	(segment
		(start 341.254334 -245.27256)
		(end 341.25408 -245.272306)
		(width 0.2032)
		(layer "F.Cu")
		(net "GND")
	)
	(segment
		(start 297.899582 -314.616592)
		(end 299.004482 -314.616592)
		(width 0.381)
		(layer "F.Cu")
		(net "GND")
	)
	(segment
		(start 357.69804 -403.94636)
		(end 357.4288 -404.2156)
		(width 0.3556)
		(layer "F.Cu")
		(net "GND")
	)
	(segment
		(start 22.123146 -313.766708)
		(end 23.228046 -313.766708)
		(width 0.381)
		(layer "F.Cu")
		(net "GND")
	)
	(segment
		(start 341.724234 -220.041724)
		(end 341.724234 -219.506038)
		(width 0.254)
		(layer "F.Cu")
		(net "GND")
	)
	(segment
		(start 199.527414 -249.166634)
		(end 200.632314 -249.166634)
		(width 0.381)
		(layer "F.Cu")
		(net "GND")
	)
	(segment
		(start 171.50588 -127.364998)
		(end 171.50588 -127.974598)
		(width 0.3556)
		(layer "F.Cu")
		(net "GND")
	)
	(segment
		(start 126.786894 -279.428194)
		(end 126.786894 -279.964134)
		(width 0.2032)
		(layer "F.Cu")
		(net "GND")
	)
	(segment
		(start 256.080514 -244.916706)
		(end 257.185414 -244.916706)
		(width 0.381)
		(layer "F.Cu")
		(net "GND")
	)
	(segment
		(start 366.268762 -268.033754)
		(end 366.269016 -268.569694)
		(width 0.254)
		(layer "F.Cu")
		(net "GND")
	)
	(segment
		(start 459.559914 -273.816572)
		(end 460.664814 -273.816572)
		(width 0.381)
		(layer "F.Cu")
		(net "GND")
	)
	(segment
		(start 107.521248 -271.011142)
		(end 107.520994 -271.011396)
		(width 0.2032)
		(layer "F.Cu")
		(net "GND")
	)
	(segment
		(start 260.180582 -247.466612)
		(end 259.075682 -247.466612)
		(width 0.381)
		(layer "F.Cu")
		(net "GND")
	)
	(segment
		(start 271.168114 -238.966756)
		(end 270.063214 -238.966756)
		(width 0.381)
		(layer "F.Cu")
		(net "GND")
	)
	(segment
		(start 361.45978 -226.553268)
		(end 361.45978 -226.017582)
		(width 0.254)
		(layer "F.Cu")
		(net "GND")
	)
	(segment
		(start 290.355782 -269.566644)
		(end 291.460682 -269.566644)
		(width 0.381)
		(layer "F.Cu")
		(net "GND")
	)
	(segment
		(start 420.736014 -267.016738)
		(end 421.840914 -267.016738)
		(width 0.381)
		(layer "F.Cu")
		(net "GND")
	)
	(segment
		(start 134.195566 -228.1809)
		(end 134.195566 -227.64496)
		(width 0.2032)
		(layer "F.Cu")
		(net "GND")
	)
	(segment
		(start 126.764542 -97.158048)
		(end 126.764542 -97.679002)
		(width 0.254)
		(layer "F.Cu")
		(net "GND")
	)
	(segment
		(start 338.93506 -55.498746)
		(end 338.394548 -55.498746)
		(width 0.2032)
		(layer "F.Cu")
		(net "GND")
	)
	(segment
		(start 178.000914 -215.166702)
		(end 176.896014 -215.166702)
		(width 0.381)
		(layer "F.Cu")
		(net "GND")
	)
	(segment
		(start 364.389162 -279.96388)
		(end 364.389416 -279.964134)
		(width 0.254)
		(layer "F.Cu")
		(net "GND")
	)
	(segment
		(start 93.783912 -233.064304)
		(end 93.784166 -233.06405)
		(width 0.254)
		(layer "F.Cu")
		(net "GND")
	)
	(segment
		(start 301.343314 -206.666592)
		(end 302.448214 -206.666592)
		(width 0.381)
		(layer "F.Cu")
		(net "GND")
	)
	(segment
		(start 377.906534 -235.506006)
		(end 377.90628 -235.505752)
		(width 0.2032)
		(layer "F.Cu")
		(net "GND")
	)
	(segment
		(start 135.02894 -347.909896)
		(end 134.35965 -347.909896)
		(width 0.3556)
		(layer "F.Cu")
		(net "GND")
	)
	(segment
		(start 107.051094 -281.05608)
		(end 107.051094 -281.591766)
		(width 0.254)
		(layer "F.Cu")
		(net "GND")
	)
	(segment
		(start 374.257316 -265.592306)
		(end 374.257316 -266.127992)
		(width 0.254)
		(layer "F.Cu")
		(net "GND")
	)
	(segment
		(start 300.022514 -236.416596)
		(end 301.343314 -236.416596)
		(width 0.381)
		(layer "F.Cu")
		(net "GND")
	)
	(segment
		(start 90.964512 -239.57534)
		(end 90.964766 -239.0394)
		(width 0.2032)
		(layer "F.Cu")
		(net "GND")
	)
	(segment
		(start 443.367414 -258.516628)
		(end 444.472314 -258.516628)
		(width 0.381)
		(layer "F.Cu")
		(net "GND")
	)
	(segment
		(start 296.794682 -286.56661)
		(end 297.899582 -286.56661)
		(width 0.381)
		(layer "F.Cu")
		(net "GND")
	)
	(segment
		(start 405.648414 -197.316598)
		(end 406.753314 -197.316598)
		(width 0.381)
		(layer "F.Cu")
		(net "GND")
	)
	(segment
		(start 254.975614 -227.066602)
		(end 256.080514 -227.066602)
		(width 0.381)
		(layer "F.Cu")
		(net "GND")
	)
	(segment
		(start 307.782214 -283.166566)
		(end 308.887114 -283.166566)
		(width 0.381)
		(layer "F.Cu")
		(net "GND")
	)
	(segment
		(start 263.624314 -227.066602)
		(end 264.729214 -227.066602)
		(width 0.381)
		(layer "F.Cu")
		(net "GND")
	)
	(segment
		(start 457.221082 -267.866622)
		(end 456.116182 -267.866622)
		(width 0.381)
		(layer "F.Cu")
		(net "GND")
	)
	(segment
		(start 338.544916 -272.103342)
		(end 338.544916 -272.639282)
		(width 0.2032)
		(layer "F.Cu")
		(net "GND")
	)
	(segment
		(start 113.519712 -240.668048)
		(end 113.52022 -240.66754)
		(width 0.254)
		(layer "F.Cu")
		(net "GND")
	)
	(segment
		(start 173.900846 -214.316564)
		(end 172.795946 -214.316564)
		(width 0.381)
		(layer "F.Cu")
		(net "GND")
	)
	(segment
		(start 12.240514 -294.216582)
		(end 13.345414 -294.216582)
		(width 0.381)
		(layer "F.Cu")
		(net "GND")
	)
	(segment
		(start 342.304116 -261.244588)
		(end 342.303862 -261.244842)
		(width 0.2032)
		(layer "F.Cu")
		(net "GND")
	)
	(segment
		(start 360.050334 -227.367084)
		(end 360.050334 -226.831144)
		(width 0.2032)
		(layer "F.Cu")
		(net "GND")
	)
	(segment
		(start 429.384714 -197.316598)
		(end 430.489614 -197.316598)
		(width 0.381)
		(layer "F.Cu")
		(net "GND")
	)
	(segment
		(start 151.997664 -58.41111)
		(end 150.867364 -58.41111)
		(width 0.3556)
		(layer "F.Cu")
		(net "GND")
	)
	(segment
		(start 379.786134 -250.155964)
		(end 379.786134 -249.620024)
		(width 0.2032)
		(layer "F.Cu")
		(net "GND")
	)
	(segment
		(start 304.338482 -202.416664)
		(end 305.443382 -202.416664)
		(width 0.381)
		(layer "F.Cu")
		(net "GND")
	)
	(segment
		(start 414.297114 -231.316784)
		(end 415.402014 -231.316784)
		(width 0.381)
		(layer "F.Cu")
		(net "GND")
	)
	(segment
		(start 262.519414 -199.01662)
		(end 263.624314 -199.01662)
		(width 0.381)
		(layer "F.Cu")
		(net "GND")
	)
	(segment
		(start 25.215596 -387.608826)
		(end 24.580596 -387.608826)
		(width 0.3556)
		(layer "F.Cu")
		(net "GND")
	)
	(segment
		(start 271.168114 -290.816792)
		(end 270.063214 -290.816792)
		(width 0.381)
		(layer "F.Cu")
		(net "GND")
	)
	(segment
		(start 18.679414 -306.96662)
		(end 19.784314 -306.96662)
		(width 0.381)
		(layer "F.Cu")
		(net "GND")
	)
	(segment
		(start 25.746964 -7.215124)
		(end 25.746964 -8.320024)
		(width 0.3556)
		(layer "F.Cu")
		(net "GND")
	)
	(segment
		(start 123.027694 -253.383796)
		(end 123.027694 -253.919736)
		(width 0.2032)
		(layer "F.Cu")
		(net "GND")
	)
	(segment
		(start 34.871914 -238.116618)
		(end 35.976814 -238.116618)
		(width 0.381)
		(layer "F.Cu")
		(net "GND")
	)
	(segment
		(start 178.000914 -269.566644)
		(end 176.896014 -269.566644)
		(width 0.381)
		(layer "F.Cu")
		(net "GND")
	)
	(segment
		(start 167.386 -23.313898)
		(end 167.386 -22.672548)
		(width 0.3556)
		(layer "F.Cu")
		(net "GND")
	)
	(segment
		(start 108.930694 -274.54479)
		(end 108.930694 -275.08073)
		(width 0.254)
		(layer "F.Cu")
		(net "GND")
	)
	(segment
		(start 277.607014 -221.96679)
		(end 278.711914 -221.96679)
		(width 0.381)
		(layer "F.Cu")
		(net "GND")
	)
	(segment
		(start 271.168114 -278.066754)
		(end 270.063214 -278.066754)
		(width 0.381)
		(layer "F.Cu")
		(net "GND")
	)
	(segment
		(start 24.332946 -227.066602)
		(end 23.228046 -227.066602)
		(width 0.381)
		(layer "F.Cu")
		(net "GND")
	)
	(segment
		(start 190.093346 -270.416782)
		(end 188.988446 -270.416782)
		(width 0.381)
		(layer "F.Cu")
		(net "GND")
	)
	(segment
		(start 413.192214 -260.21665)
		(end 414.297114 -260.21665)
		(width 0.381)
		(layer "F.Cu")
		(net "GND")
	)
	(segment
		(start 377.546362 -268.033754)
		(end 377.546616 -268.569694)
		(width 0.2032)
		(layer "F.Cu")
		(net "GND")
	)
	(segment
		(start 58.90006 -41.323768)
		(end 58.53303 -40.956738)
		(width 0.3556)
		(layer "F.Cu")
		(net "GND")
	)
	(segment
		(start 377.546362 -276.172676)
		(end 377.546616 -276.708616)
		(width 0.2032)
		(layer "F.Cu")
		(net "GND")
	)
	(segment
		(start 356.76078 -226.017582)
		(end 356.761034 -226.017328)
		(width 0.254)
		(layer "F.Cu")
		(net "GND")
	)
	(segment
		(start 26.223214 -278.916638)
		(end 27.328114 -278.916638)
		(width 0.381)
		(layer "F.Cu")
		(net "GND")
	)
	(segment
		(start 385.424934 -233.87812)
		(end 384.485134 -233.34218)
		(width 0.254)
		(layer "F.Cu")
		(net "GND")
	)
	(segment
		(start 144.77111 -40.114728)
		(end 144.77111 -40.952928)
		(width 0.3556)
		(layer "F.Cu")
		(net "GND")
	)
	(segment
		(start 326.87768 -51.32959)
		(end 326.999854 -51.451764)
		(width 0.2032)
		(layer "F.Cu")
		(net "GND")
	)
	(segment
		(start 380.835916 -268.84757)
		(end 380.835916 -269.38351)
		(width 0.2032)
		(layer "F.Cu")
		(net "GND")
	)
	(segment
		(start 57.503314 -264.466578)
		(end 58.608214 -264.466578)
		(width 0.381)
		(layer "F.Cu")
		(net "GND")
	)
	(segment
		(start 11.135614 -233.86669)
		(end 12.240514 -233.86669)
		(width 0.381)
		(layer "F.Cu")
		(net "GND")
	)
	(segment
		(start 125.737112 -220.041978)
		(end 125.737366 -220.041724)
		(width 0.254)
		(layer "F.Cu")
		(net "GND")
	)
	(segment
		(start 52.298346 -283.166566)
		(end 53.403246 -283.166566)
		(width 0.381)
		(layer "F.Cu")
		(net "GND")
	)
	(segment
		(start 382.245616 -281.591766)
		(end 382.245616 -281.59202)
		(width 0.254)
		(layer "F.Cu")
		(net "GND")
	)
	(segment
		(start 182.549546 -298.466764)
		(end 181.444646 -298.466764)
		(width 0.381)
		(layer "F.Cu")
		(net "GND")
	)
	(segment
		(start 459.559914 -234.716574)
		(end 458.455014 -234.716574)
		(width 0.381)
		(layer "F.Cu")
		(net "GND")
	)
	(segment
		(start 243.72189 -250.341384)
		(end 243.72189 -251.581158)
		(width 0.3556)
		(layer "F.Cu")
		(net "GND")
	)
	(segment
		(start 254.975614 -276.366732)
		(end 256.080514 -276.366732)
		(width 0.381)
		(layer "F.Cu")
		(net "GND")
	)
	(segment
		(start 341.72398 -247.178576)
		(end 341.724234 -247.178322)
		(width 0.2032)
		(layer "F.Cu")
		(net "GND")
	)
	(segment
		(start 12.240514 -239.81664)
		(end 13.345414 -239.81664)
		(width 0.381)
		(layer "F.Cu")
		(net "GND")
	)
	(segment
		(start 90.604848 -257.45313)
		(end 90.604848 -257.98907)
		(width 0.2032)
		(layer "F.Cu")
		(net "GND")
	)
	(segment
		(start 186.649614 -272.966688)
		(end 185.544714 -272.966688)
		(width 0.381)
		(layer "F.Cu")
		(net "GND")
	)
	(segment
		(start 39.420546 -296.766742)
		(end 38.315646 -296.766742)
		(width 0.381)
		(layer "F.Cu")
		(net "GND")
	)
	(segment
		(start 113.629694 -257.175254)
		(end 113.629948 -257.175508)
		(width 0.254)
		(layer "F.Cu")
		(net "GND")
	)
	(segment
		(start 45.859446 -238.966756)
		(end 46.964346 -238.966756)
		(width 0.381)
		(layer "F.Cu")
		(net "GND")
	)
	(segment
		(start 410.853382 -275.516594)
		(end 409.545282 -275.516594)
		(width 0.381)
		(layer "F.Cu")
		(net "GND")
	)
	(segment
		(start 305.443382 -280.61666)
		(end 306.548282 -280.61666)
		(width 0.381)
		(layer "F.Cu")
		(net "GND")
	)
	(segment
		(start 161.808414 -289.966654)
		(end 162.913314 -289.966654)
		(width 0.381)
		(layer "F.Cu")
		(net "GND")
	)
	(segment
		(start 406.753314 -311.216802)
		(end 407.858214 -311.216802)
		(width 0.381)
		(layer "F.Cu")
		(net "GND")
	)
	(segment
		(start 413.192214 -240.666778)
		(end 414.297114 -240.666778)
		(width 0.381)
		(layer "F.Cu")
		(net "GND")
	)
	(segment
		(start 32.591502 -165.599618)
		(end 32.591502 -165.761162)
		(width 0.381)
		(layer "F.Cu")
		(net "GND")
	)
	(segment
		(start 337.96478 -220.041978)
		(end 337.965034 -220.041724)
		(width 0.254)
		(layer "F.Cu")
		(net "GND")
	)
	(segment
		(start 108.820712 -231.436418)
		(end 108.820966 -231.436164)
		(width 0.2032)
		(layer "F.Cu")
		(net "GND")
	)
	(segment
		(start 352.06178 -216.250774)
		(end 352.062034 -216.25052)
		(width 0.254)
		(layer "F.Cu")
		(net "GND")
	)
	(segment
		(start 43.520614 -303.566576)
		(end 42.415714 -303.566576)
		(width 0.381)
		(layer "F.Cu")
		(net "GND")
	)
	(segment
		(start 42.415714 -211.766658)
		(end 41.310814 -211.766658)
		(width 0.381)
		(layer "F.Cu")
		(net "GND")
	)
	(segment
		(start 179.105814 -267.866622)
		(end 178.000914 -267.866622)
		(width 0.381)
		(layer "F.Cu")
		(net "GND")
	)
	(segment
		(start 428.23003 -118.34876)
		(end 427.43374 -118.34876)
		(width 0.4572)
		(layer "F.Cu")
		(net "GND")
	)
	(segment
		(start 344.073734 -230.622602)
		(end 344.07348 -230.622348)
		(width 0.2032)
		(layer "F.Cu")
		(net "GND")
	)
	(segment
		(start 92.844112 -241.203226)
		(end 92.844366 -241.202972)
		(width 0.2032)
		(layer "F.Cu")
		(net "GND")
	)
	(segment
		(start 383.185162 -269.66164)
		(end 383.185416 -270.167862)
		(width 0.2032)
		(layer "F.Cu")
		(net "GND")
	)
	(segment
		(start 309.992014 -221.96679)
		(end 308.887114 -221.96679)
		(width 0.381)
		(layer "F.Cu")
		(net "GND")
	)
	(segment
		(start 277.607014 -217.716608)
		(end 278.711914 -217.716608)
		(width 0.381)
		(layer "F.Cu")
		(net "GND")
	)
	(segment
		(start 48.854614 -310.366664)
		(end 49.959514 -310.366664)
		(width 0.381)
		(layer "F.Cu")
		(net "GND")
	)
	(segment
		(start 158.813246 -309.51678)
		(end 159.918146 -309.51678)
		(width 0.381)
		(layer "F.Cu")
		(net "GND")
	)
	(segment
		(start 22.123146 -265.316716)
		(end 23.228046 -265.316716)
		(width 0.381)
		(layer "F.Cu")
		(net "GND")
	)
	(segment
		(start 65.047114 -303.566576)
		(end 66.152014 -303.566576)
		(width 0.381)
		(layer "F.Cu")
		(net "GND")
	)
	(segment
		(start 341.364316 -286.7533)
		(end 341.364316 -287.288986)
		(width 0.254)
		(layer "F.Cu")
		(net "GND")
	)
	(segment
		(start 328.194162 -52.901596)
		(end 328.194162 -52.36718)
		(width 0.2032)
		(layer "F.Cu")
		(net "GND")
	)
	(segment
		(start 86.845648 -285.6611)
		(end 86.845394 -285.661354)
		(width 0.2032)
		(layer "F.Cu")
		(net "GND")
	)
	(segment
		(start 43.520614 -219.41663)
		(end 42.415714 -219.41663)
		(width 0.381)
		(layer "F.Cu")
		(net "GND")
	)
	(segment
		(start 33.767014 -200.716642)
		(end 34.871914 -200.716642)
		(width 0.381)
		(layer "F.Cu")
		(net "GND")
	)
	(segment
		(start 29.666946 -276.366732)
		(end 30.771846 -276.366732)
		(width 0.381)
		(layer "F.Cu")
		(net "GND")
	)
	(segment
		(start 94.254066 -246.900446)
		(end 94.254066 -246.364506)
		(width 0.2032)
		(layer "F.Cu")
		(net "GND")
	)
	(segment
		(start 130.906266 -228.99497)
		(end 130.906012 -228.994716)
		(width 0.2032)
		(layer "F.Cu")
		(net "GND")
	)
	(segment
		(start 203.7588 -92.23375)
		(end 203.7588 -91.5924)
		(width 0.3556)
		(layer "F.Cu")
		(net "GND")
	)
	(segment
		(start 357.810562 -274.54479)
		(end 357.810562 -275.08073)
		(width 0.254)
		(layer "F.Cu")
		(net "GND")
	)
	(segment
		(start 379.31598 -223.297496)
		(end 379.31598 -222.76181)
		(width 0.254)
		(layer "F.Cu")
		(net "GND")
	)
	(segment
		(start 338.544916 -280.242264)
		(end 338.544916 -280.77795)
		(width 0.1778)
		(layer "F.Cu")
		(net "GND")
	)
	(segment
		(start 119.158512 -228.1809)
		(end 119.158766 -228.180646)
		(width 0.254)
		(layer "F.Cu")
		(net "GND")
	)
	(segment
		(start 294.904414 -260.21665)
		(end 293.799514 -260.21665)
		(width 0.381)
		(layer "F.Cu")
		(net "GND")
	)
	(segment
		(start 342.66378 -222.76181)
		(end 342.664034 -222.761556)
		(width 0.254)
		(layer "F.Cu")
		(net "GND")
	)
	(segment
		(start 136.196578 -271.834356)
		(end 136.185148 -271.825212)
		(width 0.254)
		(layer "F.Cu")
		(net "GND")
	)
	(segment
		(start 128.556512 -233.064304)
		(end 128.556512 -232.528618)
		(width 0.254)
		(layer "F.Cu")
		(net "GND")
	)
	(segment
		(start 38.315646 -278.066754)
		(end 37.210746 -278.066754)
		(width 0.381)
		(layer "F.Cu")
		(net "GND")
	)
	(segment
		(start 95.303848 -286.7533)
		(end 95.303848 -287.288986)
		(width 0.254)
		(layer "F.Cu")
		(net "GND")
	)
	(segment
		(start 52.082446 -276.366732)
		(end 53.403246 -276.366732)
		(width 0.381)
		(layer "F.Cu")
		(net "GND")
	)
	(segment
		(start 26.223214 -308.666642)
		(end 27.328114 -308.666642)
		(width 0.381)
		(layer "F.Cu")
		(net "GND")
	)
	(segment
		(start 340.894162 -277.800562)
		(end 340.894162 -278.336248)
		(width 0.2032)
		(layer "F.Cu")
		(net "GND")
	)
	(segment
		(start 29.666946 -216.016586)
		(end 30.771846 -216.016586)
		(width 0.381)
		(layer "F.Cu")
		(net "GND")
	)
	(segment
		(start 87.205312 -247.714262)
		(end 87.205312 -247.178576)
		(width 0.2032)
		(layer "F.Cu")
		(net "GND")
	)
	(segment
		(start 166.357046 -279.766776)
		(end 165.252146 -279.766776)
		(width 0.381)
		(layer "F.Cu")
		(net "GND")
	)
	(segment
		(start 357.700834 -229.808532)
		(end 357.700834 -229.272846)
		(width 0.2032)
		(layer "F.Cu")
		(net "GND")
	)
	(segment
		(start 419.502082 -202.416664)
		(end 418.397182 -202.416664)
		(width 0.381)
		(layer "F.Cu")
		(net "GND")
	)
	(segment
		(start 439.923682 -269.566644)
		(end 441.028582 -269.566644)
		(width 0.381)
		(layer "F.Cu")
		(net "GND")
	)
	(segment
		(start 425.940982 -198.166736)
		(end 427.045882 -198.166736)
		(width 0.381)
		(layer "F.Cu")
		(net "GND")
	)
	(segment
		(start 342.735154 -49.859692)
		(end 343.006934 -50.329592)
		(width 0.254)
		(layer "F.Cu")
		(net "GND")
	)
	(segment
		(start 76.105512 -38.532562)
		(end 76.105512 -37.897562)
		(width 0.3556)
		(layer "F.Cu")
		(net "GND")
	)
	(segment
		(start 344.54338 -226.017582)
		(end 344.543634 -226.017328)
		(width 0.254)
		(layer "F.Cu")
		(net "GND")
	)
	(segment
		(start 290.355782 -305.266598)
		(end 291.460682 -305.266598)
		(width 0.381)
		(layer "F.Cu")
		(net "GND")
	)
	(segment
		(start 29.91993 -430.875948)
		(end 29.91993 -431.510948)
		(width 0.3556)
		(layer "F.Cu")
		(net "GND")
	)
	(segment
		(start 65.531238 -31.303722)
		(end 66.67246 -30.1625)
		(width 0.254)
		(layer "F.Cu")
		(net "GND")
	)
	(segment
		(start 416.88766 -49.831752)
		(end 415.298128 -49.831752)
		(width 0.3556)
		(layer "F.Cu")
		(net "GND")
	)
	(segment
		(start 444.472314 -261.916672)
		(end 443.367414 -261.916672)
		(width 0.381)
		(layer "F.Cu")
		(net "GND")
	)
	(segment
		(start 183.755538 -105.775506)
		(end 184.155588 -105.375456)
		(width 0.3556)
		(layer "F.Cu")
		(net "GND")
	)
	(segment
		(start 169.352214 -233.86669)
		(end 170.457114 -233.86669)
		(width 0.381)
		(layer "F.Cu")
		(net "GND")
	)
	(segment
		(start 339.374734 -227.367084)
		(end 339.374734 -226.831144)
		(width 0.2032)
		(layer "F.Cu")
		(net "GND")
	)
	(segment
		(start 370.845842 -17.221708)
		(end 371.9068 -17.221708)
		(width 0.3556)
		(layer "F.Cu")
		(net "GND")
	)
	(segment
		(start 88.725248 -286.7533)
		(end 88.725248 -287.288986)
		(width 0.254)
		(layer "F.Cu")
		(net "GND")
	)
	(segment
		(start 53.403246 -236.416596)
		(end 52.082446 -236.416596)
		(width 0.381)
		(layer "F.Cu")
		(net "GND")
	)
	(segment
		(start 176.555654 -113.77549)
		(end 176.155604 -114.17554)
		(width 0.3556)
		(layer "F.Cu")
		(net "GND")
	)
	(segment
		(start 347.641926 -52.929536)
		(end 347.619066 -52.952396)
		(width 0.2032)
		(layer "F.Cu")
		(net "GND")
	)
	(segment
		(start 282.811982 -211.766658)
		(end 283.916882 -211.766658)
		(width 0.381)
		(layer "F.Cu")
		(net "GND")
	)
	(segment
		(start 262.519414 -260.21665)
		(end 263.624314 -260.21665)
		(width 0.381)
		(layer "F.Cu")
		(net "GND")
	)
	(segment
		(start 49.959514 -289.966654)
		(end 51.064414 -289.966654)
		(width 0.381)
		(layer "F.Cu")
		(net "GND")
	)
	(segment
		(start 49.959514 -250.866656)
		(end 51.064414 -250.866656)
		(width 0.381)
		(layer "F.Cu")
		(net "GND")
	)
	(segment
		(start 100.472494 -255.011682)
		(end 100.472494 -255.547368)
		(width 0.2032)
		(layer "F.Cu")
		(net "GND")
	)
	(segment
		(start 328.244962 -50.951384)
		(end 328.625708 -50.329846)
		(width 0.254)
		(layer "F.Cu")
		(net "GND")
	)
	(segment
		(start 361.929934 -220.855794)
		(end 361.929934 -220.319854)
		(width 0.2032)
		(layer "F.Cu")
		(net "GND")
	)
	(segment
		(start 425.940982 -297.616626)
		(end 424.836082 -297.616626)
		(width 0.381)
		(layer "F.Cu")
		(net "GND")
	)
	(segment
		(start 372.377716 -263.96442)
		(end 372.377716 -264.499852)
		(width 0.2032)
		(layer "F.Cu")
		(net "GND")
	)
	(segment
		(start 464.764882 -282.316682)
		(end 463.659982 -282.316682)
		(width 0.381)
		(layer "F.Cu")
		(net "GND")
	)
	(segment
		(start 345.48318 -226.017582)
		(end 345.483434 -226.017328)
		(width 0.254)
		(layer "F.Cu")
		(net "GND")
	)
	(segment
		(start 113.519712 -239.039908)
		(end 113.519966 -239.039654)
		(width 0.254)
		(layer "F.Cu")
		(net "GND")
	)
	(segment
		(start 97.653094 -253.383796)
		(end 97.653094 -253.919482)
		(width 0.2032)
		(layer "F.Cu")
		(net "GND")
	)
	(segment
		(start 185.355738 -116.975382)
		(end 185.755788 -117.375432)
		(width 0.3556)
		(layer "F.Cu")
		(net "GND")
	)
	(segment
		(start 286.255714 -246.616728)
		(end 287.360614 -246.616728)
		(width 0.381)
		(layer "F.Cu")
		(net "GND")
	)
	(segment
		(start 181.444646 -300.166786)
		(end 180.339746 -300.166786)
		(width 0.381)
		(layer "F.Cu")
		(net "GND")
	)
	(segment
		(start 179.105814 -245.76659)
		(end 178.000914 -245.76659)
		(width 0.381)
		(layer "F.Cu")
		(net "GND")
	)
	(segment
		(start 114.099848 -272.103342)
		(end 114.099594 -272.639282)
		(width 0.2032)
		(layer "F.Cu")
		(net "GND")
	)
	(segment
		(start 406.753314 -229.616762)
		(end 407.858214 -229.616762)
		(width 0.381)
		(layer "F.Cu")
		(net "GND")
	)
	(segment
		(start 406.753314 -208.366614)
		(end 407.858214 -208.366614)
		(width 0.381)
		(layer "F.Cu")
		(net "GND")
	)
	(segment
		(start 124.797312 -226.017582)
		(end 124.797566 -226.017328)
		(width 0.254)
		(layer "F.Cu")
		(net "GND")
	)
	(segment
		(start 185.544714 -215.166702)
		(end 186.649614 -215.166702)
		(width 0.381)
		(layer "F.Cu")
		(net "GND")
	)
	(segment
		(start 11.135614 -291.666676)
		(end 12.240514 -291.666676)
		(width 0.381)
		(layer "F.Cu")
		(net "GND")
	)
	(segment
		(start 165.252146 -248.31675)
		(end 166.357046 -248.31675)
		(width 0.381)
		(layer "F.Cu")
		(net "GND")
	)
	(segment
		(start 305.443382 -303.566576)
		(end 306.548282 -303.566576)
		(width 0.381)
		(layer "F.Cu")
		(net "GND")
	)
	(segment
		(start 424.836082 -267.866622)
		(end 425.940982 -267.866622)
		(width 0.381)
		(layer "F.Cu")
		(net "GND")
	)
	(segment
		(start 301.343314 -281.466798)
		(end 302.448214 -281.466798)
		(width 0.381)
		(layer "F.Cu")
		(net "GND")
	)
	(segment
		(start 464.764882 -297.616626)
		(end 463.659982 -297.616626)
		(width 0.381)
		(layer "F.Cu")
		(net "GND")
	)
	(segment
		(start 39.420546 -300.166786)
		(end 38.315646 -300.166786)
		(width 0.381)
		(layer "F.Cu")
		(net "GND")
	)
	(segment
		(start 14.579346 -210.916774)
		(end 15.684246 -210.916774)
		(width 0.381)
		(layer "F.Cu")
		(net "GND")
	)
	(segment
		(start 137.130536 -263.686544)
		(end 137.124694 -263.686544)
		(width 0.254)
		(layer "F.Cu")
		(net "GND")
	)
	(segment
		(start 59.842146 -231.316784)
		(end 60.947046 -231.316784)
		(width 0.381)
		(layer "F.Cu")
		(net "GND")
	)
	(segment
		(start 194.193414 -262.76681)
		(end 193.088514 -262.76681)
		(width 0.381)
		(layer "F.Cu")
		(net "GND")
	)
	(segment
		(start 459.559914 -278.066754)
		(end 460.664814 -278.066754)
		(width 0.381)
		(layer "F.Cu")
		(net "GND")
	)
	(segment
		(start 311.666382 -282.316682)
		(end 312.987182 -282.316682)
		(width 0.381)
		(layer "F.Cu")
		(net "GND")
	)
	(segment
		(start 59.842146 -296.766742)
		(end 60.947046 -296.766742)
		(width 0.381)
		(layer "F.Cu")
		(net "GND")
	)
	(segment
		(start 379.31598 -220.041978)
		(end 379.31598 -219.506292)
		(width 0.254)
		(layer "F.Cu")
		(net "GND")
	)
	(segment
		(start 60.947046 -267.016738)
		(end 62.051946 -267.016738)
		(width 0.381)
		(layer "F.Cu")
		(net "GND")
	)
	(segment
		(start 128.556512 -226.017582)
		(end 128.556766 -226.017328)
		(width 0.254)
		(layer "F.Cu")
		(net "GND")
	)
	(segment
		(start 339.901276 -57.605168)
		(end 339.400896 -57.45734)
		(width 0.254)
		(layer "F.Cu")
		(net "GND")
	)
	(segment
		(start 308.887114 -203.266802)
		(end 309.992014 -203.266802)
		(width 0.381)
		(layer "F.Cu")
		(net "GND")
	)
	(segment
		(start 60.947046 -223.666558)
		(end 62.051946 -223.666558)
		(width 0.381)
		(layer "F.Cu")
		(net "GND")
	)
	(segment
		(start 371.437916 -287.288986)
		(end 371.437662 -287.28924)
		(width 0.254)
		(layer "F.Cu")
		(net "GND")
	)
	(segment
		(start 127.726694 -264.778236)
		(end 127.726948 -265.314176)
		(width 0.2032)
		(layer "F.Cu")
		(net "GND")
	)
	(segment
		(start 425.940982 -194.766692)
		(end 427.045882 -194.766692)
		(width 0.381)
		(layer "F.Cu")
		(net "GND")
	)
	(segment
		(start 338.074762 -255.011682)
		(end 338.074762 -255.547622)
		(width 0.2032)
		(layer "F.Cu")
		(net "GND")
	)
	(segment
		(start 26.496772 -404.445216)
		(end 26.596594 -404.345394)
		(width 0.3556)
		(layer "F.Cu")
		(net "GND")
	)
	(segment
		(start 456.116182 -310.366664)
		(end 455.011282 -310.366664)
		(width 0.381)
		(layer "F.Cu")
		(net "GND")
	)
	(segment
		(start 199.527414 -266.1666)
		(end 200.632314 -266.1666)
		(width 0.381)
		(layer "F.Cu")
		(net "GND")
	)
	(segment
		(start 173.900846 -204.96657)
		(end 172.795946 -204.96657)
		(width 0.381)
		(layer "F.Cu")
		(net "GND")
	)
	(segment
		(start 433.484782 -294.216582)
		(end 434.589682 -294.216582)
		(width 0.381)
		(layer "F.Cu")
		(net "GND")
	)
	(segment
		(start 413.192214 -217.716608)
		(end 414.297114 -217.716608)
		(width 0.381)
		(layer "F.Cu")
		(net "GND")
	)
	(segment
		(start 56.398414 -277.216616)
		(end 57.503314 -277.216616)
		(width 0.381)
		(layer "F.Cu")
		(net "GND")
	)
	(segment
		(start 214.615014 -215.166702)
		(end 215.719914 -215.166702)
		(width 0.381)
		(layer "F.Cu")
		(net "GND")
	)
	(segment
		(start 384.109976 -74.11593)
		(end 384.109976 -74.694034)
		(width 0.1778)
		(layer "F.Cu")
		(net "GND")
	)
	(segment
		(start 381.19558 -226.553268)
		(end 381.19558 -226.017582)
		(width 0.254)
		(layer "F.Cu")
		(net "GND")
	)
	(segment
		(start 452.016114 -281.466798)
		(end 450.911214 -281.466798)
		(width 0.381)
		(layer "F.Cu")
		(net "GND")
	)
	(segment
		(start 419.749986 -216.866724)
		(end 418.397182 -216.866724)
		(width 0.381)
		(layer "F.Cu")
		(net "GND")
	)
	(segment
		(start 346.532962 -285.939484)
		(end 346.532962 -286.475424)
		(width 0.2032)
		(layer "F.Cu")
		(net "GND")
	)
	(segment
		(start 182.82158 -410.80563)
		(end 182.82158 -410.10586)
		(width 0.3556)
		(layer "F.Cu")
		(net "GND")
	)
	(segment
		(start 104.121712 -226.553268)
		(end 104.121712 -226.017582)
		(width 0.254)
		(layer "F.Cu")
		(net "GND")
	)
	(segment
		(start 53.07457 -154.077924)
		(end 53.07457 -153.725626)
		(width 0.2032)
		(layer "F.Cu")
		(net "GND")
	)
	(segment
		(start 336.555334 -225.739198)
		(end 336.555334 -225.203258)
		(width 0.2032)
		(layer "F.Cu")
		(net "GND")
	)
	(segment
		(start 377.076716 -254.197612)
		(end 377.076716 -254.733298)
		(width 0.254)
		(layer "F.Cu")
		(net "GND")
	)
	(segment
		(start 115.039648 -263.96442)
		(end 115.039648 -264.499852)
		(width 0.254)
		(layer "F.Cu")
		(net "GND")
	)
	(segment
		(start 87.675466 -215.436958)
		(end 87.675212 -215.436704)
		(width 0.2032)
		(layer "F.Cu")
		(net "GND")
	)
	(segment
		(start 158.813246 -265.316716)
		(end 157.708346 -265.316716)
		(width 0.381)
		(layer "F.Cu")
		(net "GND")
	)
	(segment
		(start 8.140446 -300.166786)
		(end 9.245346 -300.166786)
		(width 0.381)
		(layer "F.Cu")
		(net "GND")
	)
	(segment
		(start 297.899582 -267.866622)
		(end 299.004482 -267.866622)
		(width 0.381)
		(layer "F.Cu")
		(net "GND")
	)
	(segment
		(start 371.797834 -220.041724)
		(end 371.797834 -219.506038)
		(width 0.254)
		(layer "F.Cu")
		(net "GND")
	)
	(segment
		(start 366.159034 -229.808532)
		(end 366.159034 -229.272846)
		(width 0.254)
		(layer "F.Cu")
		(net "GND")
	)
	(segment
		(start 15.684246 -317.166752)
		(end 16.789146 -317.166752)
		(width 0.381)
		(layer "F.Cu")
		(net "GND")
	)
	(segment
		(start 70.33006 -63.251588)
		(end 70.41896 -63.162688)
		(width 0.3556)
		(layer "F.Cu")
		(net "GND")
	)
	(segment
		(start 342.773762 -277.800562)
		(end 342.773762 -278.336248)
		(width 0.2032)
		(layer "F.Cu")
		(net "GND")
	)
	(segment
		(start 421.840914 -236.416596)
		(end 423.226484 -236.416596)
		(width 0.381)
		(layer "F.Cu")
		(net "GND")
	)
	(segment
		(start 261.285482 -216.866724)
		(end 260.180582 -216.866724)
		(width 0.381)
		(layer "F.Cu")
		(net "GND")
	)
	(segment
		(start 360.98988 -238.76127)
		(end 360.98988 -238.225584)
		(width 0.254)
		(layer "F.Cu")
		(net "GND")
	)
	(segment
		(start 30.771846 -220.266768)
		(end 31.876746 -220.266768)
		(width 0.381)
		(layer "F.Cu")
		(net "GND")
	)
	(segment
		(start 158.813246 -301.866808)
		(end 160.178242 -301.866808)
		(width 0.381)
		(layer "F.Cu")
		(net "GND")
	)
	(segment
		(start 127.257048 -279.150064)
		(end 127.256794 -279.150318)
		(width 0.254)
		(layer "F.Cu")
		(net "GND")
	)
	(segment
		(start 86.159594 -338.951316)
		(end 85.813138 -339.297772)
		(width 0.1778)
		(layer "F.Cu")
		(net "GND")
	)
	(segment
		(start 346.063316 -283.497782)
		(end 346.063316 -284.033468)
		(width 0.254)
		(layer "F.Cu")
		(net "GND")
	)
	(segment
		(start 158.813246 -304.416714)
		(end 157.708346 -304.416714)
		(width 0.381)
		(layer "F.Cu")
		(net "GND")
	)
	(segment
		(start 271.168114 -296.766742)
		(end 270.063214 -296.766742)
		(width 0.381)
		(layer "F.Cu")
		(net "GND")
	)
	(segment
		(start 57.503314 -232.166668)
		(end 58.608214 -232.166668)
		(width 0.381)
		(layer "F.Cu")
		(net "GND")
	)
	(segment
		(start 293.799514 -265.316716)
		(end 292.694614 -265.316716)
		(width 0.381)
		(layer "F.Cu")
		(net "GND")
	)
	(segment
		(start 380.365762 -281.05608)
		(end 380.365762 -281.591512)
		(width 0.254)
		(layer "F.Cu")
		(net "GND")
	)
	(segment
		(start 290.355782 -286.56661)
		(end 291.460682 -286.56661)
		(width 0.381)
		(layer "F.Cu")
		(net "GND")
	)
	(segment
		(start 311.882282 -305.266598)
		(end 312.987182 -305.266598)
		(width 0.381)
		(layer "F.Cu")
		(net "GND")
	)
	(segment
		(start 375.55678 -233.064304)
		(end 375.55678 -232.528618)
		(width 0.254)
		(layer "F.Cu")
		(net "GND")
	)
	(segment
		(start 121.038112 -226.017582)
		(end 121.038366 -226.017328)
		(width 0.254)
		(layer "F.Cu")
		(net "GND")
	)
	(segment
		(start 210.514946 -258.516628)
		(end 211.619846 -258.516628)
		(width 0.381)
		(layer "F.Cu")
		(net "GND")
	)
	(segment
		(start 185.544714 -278.916638)
		(end 184.439814 -278.916638)
		(width 0.381)
		(layer "F.Cu")
		(net "GND")
	)
	(segment
		(start 422.945814 -300.166786)
		(end 421.840914 -300.166786)
		(width 0.381)
		(layer "F.Cu")
		(net "GND")
	)
	(segment
		(start 129.496566 -231.436164)
		(end 129.496566 -230.900478)
		(width 0.2032)
		(layer "F.Cu")
		(net "GND")
	)
	(segment
		(start 187.883546 -298.466764)
		(end 188.988446 -298.466764)
		(width 0.381)
		(layer "F.Cu")
		(net "GND")
	)
	(segment
		(start 307.782214 -290.816792)
		(end 308.887114 -290.816792)
		(width 0.381)
		(layer "F.Cu")
		(net "GND")
	)
	(segment
		(start 116.449348 -270.167862)
		(end 116.449348 -270.19758)
		(width 0.2032)
		(layer "F.Cu")
		(net "GND")
	)
	(segment
		(start 433.166774 -8.320024)
		(end 433.166774 -7.215124)
		(width 0.3556)
		(layer "F.Cu")
		(net "GND")
	)
	(segment
		(start 59.842146 -244.916706)
		(end 60.947046 -244.916706)
		(width 0.381)
		(layer "F.Cu")
		(net "GND")
	)
	(segment
		(start 117.368066 -398.697958)
		(end 117.368066 -399.332958)
		(width 0.3556)
		(layer "F.Cu")
		(net "GND")
	)
	(segment
		(start 280.410158 -425.69638)
		(end 280.532078 -425.57446)
		(width 0.3556)
		(layer "F.Cu")
		(net "GND")
	)
	(segment
		(start 52.298346 -238.966756)
		(end 53.403246 -238.966756)
		(width 0.381)
		(layer "F.Cu")
		(net "GND")
	)
	(segment
		(start 349.71228 -243.644674)
		(end 349.71228 -243.108988)
		(width 0.254)
		(layer "F.Cu")
		(net "GND")
	)
	(segment
		(start 372.26748 -245.272306)
		(end 372.26748 -244.73662)
		(width 0.2032)
		(layer "F.Cu")
		(net "GND")
	)
	(segment
		(start 344.07348 -232.250234)
		(end 344.07348 -231.714548)
		(width 0.2032)
		(layer "F.Cu")
		(net "GND")
	)
	(segment
		(start 375.55678 -246.08663)
		(end 375.55678 -245.55069)
		(width 0.2032)
		(layer "F.Cu")
		(net "GND")
	)
	(segment
		(start 43.520614 -235.566712)
		(end 42.415714 -235.566712)
		(width 0.381)
		(layer "F.Cu")
		(net "GND")
	)
	(segment
		(start 370.498116 -255.825498)
		(end 370.498116 -256.361438)
		(width 0.2032)
		(layer "F.Cu")
		(net "GND")
	)
	(segment
		(start 60.947046 -210.916774)
		(end 62.051946 -210.916774)
		(width 0.381)
		(layer "F.Cu")
		(net "GND")
	)
	(segment
		(start 53.403246 -261.916672)
		(end 54.508146 -261.916672)
		(width 0.3556)
		(layer "F.Cu")
		(net "GND")
	)
	(segment
		(start 462.555082 -258.516628)
		(end 463.659982 -258.516628)
		(width 0.381)
		(layer "F.Cu")
		(net "GND")
	)
	(segment
		(start 286.255714 -248.31675)
		(end 287.360614 -248.31675)
		(width 0.381)
		(layer "F.Cu")
		(net "GND")
	)
	(segment
		(start 117.604794 -102.883462)
		(end 117.604794 -104.213914)
		(width 0.3556)
		(layer "F.Cu")
		(net "GND")
	)
	(segment
		(start 336.665316 -267.755624)
		(end 336.665062 -267.755878)
		(width 0.2032)
		(layer "F.Cu")
		(net "GND")
	)
	(segment
		(start 414.297114 -240.666778)
		(end 415.402014 -240.666778)
		(width 0.381)
		(layer "F.Cu")
		(net "GND")
	)
	(segment
		(start 261.285482 -280.61666)
		(end 260.180582 -280.61666)
		(width 0.381)
		(layer "F.Cu")
		(net "GND")
	)
	(segment
		(start 256.080514 -298.466764)
		(end 257.185414 -298.466764)
		(width 0.381)
		(layer "F.Cu")
		(net "GND")
	)
	(segment
		(start 339.37448 -246.900192)
		(end 339.37448 -246.364506)
		(width 0.2032)
		(layer "F.Cu")
		(net "GND")
	)
	(segment
		(start 53.403246 -263.616694)
		(end 54.508146 -263.616694)
		(width 0.381)
		(layer "F.Cu")
		(net "GND")
	)
	(segment
		(start 420.736014 -208.366614)
		(end 421.840914 -208.366614)
		(width 0.381)
		(layer "F.Cu")
		(net "GND")
	)
	(segment
		(start 266.619482 -239.81664)
		(end 267.724382 -239.81664)
		(width 0.381)
		(layer "F.Cu")
		(net "GND")
	)
	(segment
		(start 184.439814 -282.316682)
		(end 185.544714 -282.316682)
		(width 0.381)
		(layer "F.Cu")
		(net "GND")
	)
	(segment
		(start 107.521248 -286.7533)
		(end 107.521248 -287.288986)
		(width 0.254)
		(layer "F.Cu")
		(net "GND")
	)
	(segment
		(start 448.572382 -196.466714)
		(end 449.677282 -196.466714)
		(width 0.381)
		(layer "F.Cu")
		(net "GND")
	)
	(segment
		(start 335.255362 -264.778236)
		(end 335.255362 -265.314176)
		(width 0.2032)
		(layer "F.Cu")
		(net "GND")
	)
	(segment
		(start 421.840914 -199.01662)
		(end 422.945814 -199.01662)
		(width 0.381)
		(layer "F.Cu")
		(net "GND")
	)
	(segment
		(start 271.168114 -268.71676)
		(end 270.063214 -268.71676)
		(width 0.381)
		(layer "F.Cu")
		(net "GND")
	)
	(segment
		(start 22.123146 -195.616576)
		(end 23.228046 -195.616576)
		(width 0.381)
		(layer "F.Cu")
		(net "GND")
	)
	(segment
		(start 271.168114 -263.616694)
		(end 270.063214 -263.616694)
		(width 0.381)
		(layer "F.Cu")
		(net "GND")
	)
	(segment
		(start 214.615014 -269.566644)
		(end 215.719914 -269.566644)
		(width 0.381)
		(layer "F.Cu")
		(net "GND")
	)
	(segment
		(start 110.340648 -283.497782)
		(end 110.340648 -284.033468)
		(width 0.254)
		(layer "F.Cu")
		(net "GND")
	)
	(segment
		(start 456.734672 -107.018836)
		(end 456.048872 -107.018836)
		(width 0.3556)
		(layer "F.Cu")
		(net "GND")
	)
	(segment
		(start 418.397182 -312.91657)
		(end 417.081716 -312.91657)
		(width 0.381)
		(layer "F.Cu")
		(net "GND")
	)
	(segment
		(start 346.42298 -242.295172)
		(end 346.423234 -242.294918)
		(width 0.2032)
		(layer "F.Cu")
		(net "GND")
	)
	(segment
		(start 283.916882 -200.716642)
		(end 282.811982 -200.716642)
		(width 0.381)
		(layer "F.Cu")
		(net "GND")
	)
	(segment
		(start 386.83438 -244.458744)
		(end 387.568694 -244.458744)
		(width 0.254)
		(layer "F.Cu")
		(net "GND")
	)
	(segment
		(start 407.446988 -11.26998)
		(end 407.446988 -12.37488)
		(width 0.3556)
		(layer "F.Cu")
		(net "GND")
	)
	(segment
		(start 23.228046 -234.716574)
		(end 24.332946 -234.716574)
		(width 0.381)
		(layer "F.Cu")
		(net "GND")
	)
	(segment
		(start 458.629766 -97.864422)
		(end 457.943966 -97.864422)
		(width 0.3556)
		(layer "F.Cu")
		(net "GND")
	)
	(segment
		(start 370.498116 -284.033468)
		(end 370.497862 -284.033722)
		(width 0.254)
		(layer "F.Cu")
		(net "GND")
	)
	(segment
		(start 111.170466 -230.622602)
		(end 111.170466 -230.086662)
		(width 0.2032)
		(layer "F.Cu")
		(net "GND")
	)
	(segment
		(start 210.514946 -217.716608)
		(end 211.619846 -217.716608)
		(width 0.381)
		(layer "F.Cu")
		(net "GND")
	)
	(segment
		(start 191.983614 -282.316682)
		(end 193.088514 -282.316682)
		(width 0.381)
		(layer "F.Cu")
		(net "GND")
	)
	(segment
		(start 104.121712 -233.064304)
		(end 104.121966 -233.06405)
		(width 0.254)
		(layer "F.Cu")
		(net "GND")
	)
	(segment
		(start 7.035546 -315.46673)
		(end 8.140446 -315.46673)
		(width 0.381)
		(layer "F.Cu")
		(net "GND")
	)
	(segment
		(start 88.145366 -215.158574)
		(end 88.145366 -214.622888)
		(width 0.1778)
		(layer "F.Cu")
		(net "GND")
	)
	(segment
		(start 296.794682 -288.266632)
		(end 297.899582 -288.266632)
		(width 0.381)
		(layer "F.Cu")
		(net "GND")
	)
	(segment
		(start 384.609848 -78.31074)
		(end 384.609848 -77.594206)
		(width 0.254)
		(layer "F.Cu")
		(net "GND")
	)
	(segment
		(start 7.035546 -216.016586)
		(end 8.140446 -216.016586)
		(width 0.381)
		(layer "F.Cu")
		(net "GND")
	)
	(segment
		(start 294.904414 -311.216802)
		(end 293.799514 -311.216802)
		(width 0.381)
		(layer "F.Cu")
		(net "GND")
	)
	(segment
		(start 350.18218 -216.78646)
		(end 350.18218 -216.250774)
		(width 0.254)
		(layer "F.Cu")
		(net "GND")
	)
	(segment
		(start 290.355782 -316.316614)
		(end 291.460682 -316.316614)
		(width 0.381)
		(layer "F.Cu")
		(net "GND")
	)
	(segment
		(start 33.767014 -239.81664)
		(end 34.871914 -239.81664)
		(width 0.381)
		(layer "F.Cu")
		(net "GND")
	)
	(segment
		(start 285.150814 -306.116736)
		(end 286.255714 -306.116736)
		(width 0.381)
		(layer "F.Cu")
		(net "GND")
	)
	(segment
		(start 134.305294 -253.919482)
		(end 134.305548 -253.919736)
		(width 0.2032)
		(layer "F.Cu")
		(net "GND")
	)
	(segment
		(start 183.755538 -120.975374)
		(end 184.155588 -121.375424)
		(width 0.3556)
		(layer "F.Cu")
		(net "GND")
	)
	(segment
		(start 87.675466 -215.972644)
		(end 87.675466 -215.436958)
		(width 0.2032)
		(layer "F.Cu")
		(net "GND")
	)
	(segment
		(start 45.859446 -263.616694)
		(end 46.964346 -263.616694)
		(width 0.381)
		(layer "F.Cu")
		(net "GND")
	)
	(segment
		(start 254.975614 -296.766742)
		(end 256.080514 -296.766742)
		(width 0.381)
		(layer "F.Cu")
		(net "GND")
	)
	(segment
		(start 435.823614 -273.816572)
		(end 436.928514 -273.816572)
		(width 0.381)
		(layer "F.Cu")
		(net "GND")
	)
	(segment
		(start 178.1556 -112.175544)
		(end 177.75555 -111.775494)
		(width 0.3556)
		(layer "F.Cu")
		(net "GND")
	)
	(segment
		(start 293.799514 -261.916672)
		(end 292.694614 -261.916672)
		(width 0.381)
		(layer "F.Cu")
		(net "GND")
	)
	(segment
		(start 312.987182 -310.366664)
		(end 314.307982 -310.366664)
		(width 0.381)
		(layer "F.Cu")
		(net "GND")
	)
	(segment
		(start 340.78418 -233.064304)
		(end 340.784434 -233.06405)
		(width 0.254)
		(layer "F.Cu")
		(net "GND")
	)
	(segment
		(start 101.772212 -238.76127)
		(end 101.772212 -238.225584)
		(width 0.2032)
		(layer "F.Cu")
		(net "GND")
	)
	(segment
		(start 92.954094 -276.172676)
		(end 92.954094 -276.708362)
		(width 0.2032)
		(layer "F.Cu")
		(net "GND")
	)
	(segment
		(start 458.455014 -281.466798)
		(end 459.559914 -281.466798)
		(width 0.381)
		(layer "F.Cu")
		(net "GND")
	)
	(segment
		(start 452.016114 -304.416714)
		(end 450.911214 -304.416714)
		(width 0.381)
		(layer "F.Cu")
		(net "GND")
	)
	(segment
		(start 371.907562 -281.05608)
		(end 371.907562 -281.591512)
		(width 0.254)
		(layer "F.Cu")
		(net "GND")
	)
	(segment
		(start 42.415714 -310.366664)
		(end 43.520614 -310.366664)
		(width 0.381)
		(layer "F.Cu")
		(net "GND")
	)
	(segment
		(start 12.240514 -305.266598)
		(end 13.345414 -305.266598)
		(width 0.381)
		(layer "F.Cu")
		(net "GND")
	)
	(segment
		(start 453.121014 -296.766742)
		(end 452.016114 -296.766742)
		(width 0.381)
		(layer "F.Cu")
		(net "GND")
	)
	(segment
		(start 372.26748 -250.15571)
		(end 372.26748 -249.620024)
		(width 0.2032)
		(layer "F.Cu")
		(net "GND")
	)
	(segment
		(start 86.375494 -255.011682)
		(end 86.845394 -254.733552)
		(width 0.254)
		(layer "F.Cu")
		(net "GND")
	)
	(segment
		(start 108.820966 -234.691936)
		(end 108.820966 -234.15625)
		(width 0.254)
		(layer "F.Cu")
		(net "GND")
	)
	(segment
		(start 91.434666 -238.225584)
		(end 91.434666 -238.761524)
		(width 0.2032)
		(layer "F.Cu")
		(net "GND")
	)
	(segment
		(start 256.080514 -278.066754)
		(end 257.185414 -278.066754)
		(width 0.381)
		(layer "F.Cu")
		(net "GND")
	)
	(segment
		(start 453.121014 -250.016772)
		(end 452.016114 -250.016772)
		(width 0.381)
		(layer "F.Cu")
		(net "GND")
	)
	(segment
		(start 351.702116 -287.288986)
		(end 351.701862 -287.28924)
		(width 0.254)
		(layer "F.Cu")
		(net "GND")
	)
	(segment
		(start 124.437648 -284.033468)
		(end 124.437394 -284.033722)
		(width 0.254)
		(layer "F.Cu")
		(net "GND")
	)
	(segment
		(start 367.09858 -222.76181)
		(end 367.098834 -222.761556)
		(width 0.254)
		(layer "F.Cu")
		(net "GND")
	)
	(segment
		(start 102.821994 -270.47571)
		(end 102.821994 -271.011396)
		(width 0.2032)
		(layer "F.Cu")
		(net "GND")
	)
	(segment
		(start 282.811982 -226.216718)
		(end 283.916882 -226.216718)
		(width 0.381)
		(layer "F.Cu")
		(net "GND")
	)
	(segment
		(start 439.923682 -316.316614)
		(end 441.028582 -316.316614)
		(width 0.381)
		(layer "F.Cu")
		(net "GND")
	)
	(segment
		(start 433.484782 -301.01667)
		(end 434.589682 -301.01667)
		(width 0.381)
		(layer "F.Cu")
		(net "GND")
	)
	(segment
		(start 45.859446 -231.316784)
		(end 46.964346 -231.316784)
		(width 0.381)
		(layer "F.Cu")
		(net "GND")
	)
	(segment
		(start 289.250882 -258.516628)
		(end 290.355782 -258.516628)
		(width 0.381)
		(layer "F.Cu")
		(net "GND")
	)
	(segment
		(start 345.953334 -246.900446)
		(end 345.95308 -246.900192)
		(width 0.2032)
		(layer "F.Cu")
		(net "GND")
	)
	(segment
		(start 166.357046 -231.316784)
		(end 167.461946 -231.316784)
		(width 0.381)
		(layer "F.Cu")
		(net "GND")
	)
	(segment
		(start 368.97818 -216.78646)
		(end 368.97818 -216.250774)
		(width 0.254)
		(layer "F.Cu")
		(net "GND")
	)
	(segment
		(start 357.70058 -222.76181)
		(end 357.700834 -222.761556)
		(width 0.254)
		(layer "F.Cu")
		(net "GND")
	)
	(segment
		(start 345.593416 -268.034008)
		(end 345.593416 -268.569694)
		(width 0.2032)
		(layer "F.Cu")
		(net "GND")
	)
	(segment
		(start 50.360834 -152.564592)
		(end 50.785014 -152.564592)
		(width 0.381)
		(layer "F.Cu")
		(net "GND")
	)
	(segment
		(start 215.719914 -250.866656)
		(end 216.824814 -250.866656)
		(width 0.381)
		(layer "F.Cu")
		(net "GND")
	)
	(segment
		(start 188.988446 -214.316564)
		(end 187.883546 -214.316564)
		(width 0.381)
		(layer "F.Cu")
		(net "GND")
	)
	(segment
		(start 90.964766 -229.808532)
		(end 90.964766 -229.272846)
		(width 0.2032)
		(layer "F.Cu")
		(net "GND")
	)
	(segment
		(start 302.814482 -424.033188)
		(end 303.322482 -424.033188)
		(width 0.3556)
		(layer "F.Cu")
		(net "GND")
	)
	(segment
		(start 405.64689 -11.26998)
		(end 405.64689 -12.37488)
		(width 0.3556)
		(layer "F.Cu")
		(net "GND")
	)
	(segment
		(start 276.373082 -226.216718)
		(end 275.268182 -226.216718)
		(width 0.381)
		(layer "F.Cu")
		(net "GND")
	)
	(segment
		(start 52.298346 -242.3668)
		(end 53.403246 -242.3668)
		(width 0.381)
		(layer "F.Cu")
		(net "GND")
	)
	(segment
		(start 296.794682 -196.466714)
		(end 297.899582 -196.466714)
		(width 0.381)
		(layer "F.Cu")
		(net "GND")
	)
	(segment
		(start 336.899758 -59.889136)
		(end 336.899758 -59.265312)
		(width 0.2032)
		(layer "F.Cu")
		(net "GND")
	)
	(segment
		(start 308.887114 -250.016772)
		(end 309.992014 -250.016772)
		(width 0.381)
		(layer "F.Cu")
		(net "GND")
	)
	(segment
		(start 404.341076 -62.999112)
		(end 404.346156 -62.994032)
		(width 0.3556)
		(layer "F.Cu")
		(net "GND")
	)
	(segment
		(start 328.110342 -22.261576)
		(end 328.123042 -22.274276)
		(width 0.3556)
		(layer "F.Cu")
		(net "GND")
	)
	(segment
		(start 369.448334 -227.367084)
		(end 369.448334 -226.831144)
		(width 0.2032)
		(layer "F.Cu")
		(net "GND")
	)
	(segment
		(start 184.439814 -299.316648)
		(end 185.544714 -299.316648)
		(width 0.381)
		(layer "F.Cu")
		(net "GND")
	)
	(segment
		(start 112.110266 -220.855794)
		(end 112.110266 -220.319854)
		(width 0.2032)
		(layer "F.Cu")
		(net "GND")
	)
	(segment
		(start 118.798848 -275.35886)
		(end 118.798848 -275.8948)
		(width 0.254)
		(layer "F.Cu")
		(net "GND")
	)
	(segment
		(start 199.527414 -272.966688)
		(end 200.632314 -272.966688)
		(width 0.381)
		(layer "F.Cu")
		(net "GND")
	)
	(segment
		(start 304.338482 -200.716642)
		(end 305.443382 -200.716642)
		(width 0.381)
		(layer "F.Cu")
		(net "GND")
	)
	(segment
		(start 413.192214 -212.616796)
		(end 414.297114 -212.616796)
		(width 0.381)
		(layer "F.Cu")
		(net "GND")
	)
	(segment
		(start 164.018214 -228.766624)
		(end 162.913314 -228.766624)
		(width 0.381)
		(layer "F.Cu")
		(net "GND")
	)
	(segment
		(start 99.532694 -262.058404)
		(end 99.532948 -262.058658)
		(width 0.254)
		(layer "F.Cu")
		(net "GND")
	)
	(segment
		(start 380.72568 -242.016788)
		(end 380.72568 -241.481102)
		(width 0.2032)
		(layer "F.Cu")
		(net "GND")
	)
	(segment
		(start 427.826424 -120.97766)
		(end 427.826424 -121.61266)
		(width 0.381)
		(layer "F.Cu")
		(net "GND")
	)
	(segment
		(start 208.176114 -222.816674)
		(end 209.281014 -222.816674)
		(width 0.381)
		(layer "F.Cu")
		(net "GND")
	)
	(segment
		(start 448.572382 -204.116686)
		(end 447.467482 -204.116686)
		(width 0.381)
		(layer "F.Cu")
		(net "GND")
	)
	(segment
		(start 419.502082 -233.86669)
		(end 418.397182 -233.86669)
		(width 0.381)
		(layer "F.Cu")
		(net "GND")
	)
	(segment
		(start 150.21433 -32.929068)
		(end 150.21433 -33.564068)
		(width 0.3556)
		(layer "F.Cu")
		(net "GND")
	)
	(segment
		(start 375.666762 -264.778236)
		(end 375.667016 -265.314176)
		(width 0.2032)
		(layer "F.Cu")
		(net "GND")
	)
	(segment
		(start 335.615534 -224.111566)
		(end 335.615534 -223.575626)
		(width 0.254)
		(layer "F.Cu")
		(net "GND")
	)
	(segment
		(start 172.795946 -281.466798)
		(end 173.900846 -281.466798)
		(width 0.381)
		(layer "F.Cu")
		(net "GND")
	)
	(segment
		(start 379.31598 -226.017582)
		(end 379.316234 -226.017328)
		(width 0.254)
		(layer "F.Cu")
		(net "GND")
	)
	(segment
		(start 433.484782 -264.466578)
		(end 434.589682 -264.466578)
		(width 0.381)
		(layer "F.Cu")
		(net "GND")
	)
	(segment
		(start 28.978098 -76.924916)
		(end 28.978098 -76.289916)
		(width 0.3556)
		(layer "F.Cu")
		(net "GND")
	)
	(segment
		(start 165.546786 -128.086358)
		(end 164.901372 -128.086358)
		(width 0.3556)
		(layer "F.Cu")
		(net "GND")
	)
	(segment
		(start 137.594594 -263.96442)
		(end 137.153396 -263.709404)
		(width 0.254)
		(layer "F.Cu")
		(net "GND")
	)
	(segment
		(start 5.694426 -98.516694)
		(end 5.644642 -98.566478)
		(width 0.3556)
		(layer "F.Cu")
		(net "GND")
	)
	(segment
		(start 330.79436 -54.558946)
		(end 330.252578 -54.558946)
		(width 0.2032)
		(layer "F.Cu")
		(net "GND")
	)
	(segment
		(start 130.906012 -235.505752)
		(end 130.906012 -234.970066)
		(width 0.2032)
		(layer "F.Cu")
		(net "GND")
	)
	(segment
		(start 86.265766 -234.69219)
		(end 86.735412 -234.970066)
		(width 0.2032)
		(layer "F.Cu")
		(net "GND")
	)
	(segment
		(start 452.016114 -296.766742)
		(end 450.911214 -296.766742)
		(width 0.381)
		(layer "F.Cu")
		(net "GND")
	)
	(segment
		(start 374.257316 -281.869896)
		(end 374.257316 -282.405836)
		(width 0.254)
		(layer "F.Cu")
		(net "GND")
	)
	(segment
		(start 378.376434 -247.714008)
		(end 378.376434 -247.178322)
		(width 0.2032)
		(layer "F.Cu")
		(net "GND")
	)
	(segment
		(start 22.123146 -242.3668)
		(end 23.228046 -242.3668)
		(width 0.381)
		(layer "F.Cu")
		(net "GND")
	)
	(segment
		(start 345.554554 -47.95012)
		(end 345.96959 -47.44974)
		(width 0.2032)
		(layer "F.Cu")
		(net "GND")
	)
	(segment
		(start 298.62018 -48.304196)
		(end 298.62018 -49.320196)
		(width 0.3556)
		(layer "F.Cu")
		(net "GND")
	)
	(segment
		(start 381.126238 -365.016034)
		(end 381.750824 -365.64062)
		(width 0.508)
		(layer "F.Cu")
		(net "GND")
	)
	(segment
		(start 435.823614 -214.316564)
		(end 436.928514 -214.316564)
		(width 0.381)
		(layer "F.Cu")
		(net "GND")
	)
	(segment
		(start 127.288544 -78.521052)
		(end 127.288544 -79.308452)
		(width 0.254)
		(layer "F.Cu")
		(net "GND")
	)
	(segment
		(start 104.42575 -407.289)
		(end 103.8098 -407.289)
		(width 0.3556)
		(layer "F.Cu")
		(net "GND")
	)
	(segment
		(start 282.811982 -314.616592)
		(end 283.916882 -314.616592)
		(width 0.381)
		(layer "F.Cu")
		(net "GND")
	)
	(segment
		(start 428.279814 -201.56678)
		(end 429.384714 -201.56678)
		(width 0.381)
		(layer "F.Cu")
		(net "GND")
	)
	(segment
		(start 326.584818 -57.954926)
		(end 326.999854 -57.454546)
		(width 0.2032)
		(layer "F.Cu")
		(net "GND")
	)
	(segment
		(start 93.195394 -338.796884)
		(end 93.193362 -338.798916)
		(width 0.381)
		(layer "F.Cu")
		(net "GND")
	)
	(segment
		(start 305.443382 -202.416664)
		(end 306.548282 -202.416664)
		(width 0.381)
		(layer "F.Cu")
		(net "GND")
	)
	(segment
		(start 281.707082 -198.166736)
		(end 282.811982 -198.166736)
		(width 0.381)
		(layer "F.Cu")
		(net "GND")
	)
	(segment
		(start 421.292528 -344.017346)
		(end 422.232836 -344.017346)
		(width 0.508)
		(layer "F.Cu")
		(net "GND")
	)
	(segment
		(start 202.971146 -236.416596)
		(end 204.076046 -236.416596)
		(width 0.381)
		(layer "F.Cu")
		(net "GND")
	)
	(segment
		(start 301.343314 -223.666558)
		(end 302.448214 -223.666558)
		(width 0.381)
		(layer "F.Cu")
		(net "GND")
	)
	(segment
		(start 314.092082 -226.216718)
		(end 312.987182 -226.216718)
		(width 0.381)
		(layer "F.Cu")
		(net "GND")
	)
	(segment
		(start 339.014562 -289.195002)
		(end 339.014562 -289.807142)
		(width 0.2032)
		(layer "F.Cu")
		(net "GND")
	)
	(segment
		(start 127.239776 -338.951316)
		(end 126.960122 -338.951316)
		(width 0.1778)
		(layer "F.Cu")
		(net "GND")
	)
	(segment
		(start 350.18218 -223.297496)
		(end 350.18218 -222.76181)
		(width 0.254)
		(layer "F.Cu")
		(net "GND")
	)
	(segment
		(start 300.238414 -260.21665)
		(end 301.343314 -260.21665)
		(width 0.381)
		(layer "F.Cu")
		(net "GND")
	)
	(segment
		(start 335.615534 -227.367084)
		(end 335.615534 -226.831144)
		(width 0.254)
		(layer "F.Cu")
		(net "GND")
	)
	(segment
		(start 178.000914 -211.766658)
		(end 179.105814 -211.766658)
		(width 0.381)
		(layer "F.Cu")
		(net "GND")
	)
	(segment
		(start 373.67718 -246.08663)
		(end 373.67718 -245.55069)
		(width 0.2032)
		(layer "F.Cu")
		(net "GND")
	)
	(segment
		(start 55.066946 -9.424924)
		(end 55.066946 -8.320024)
		(width 0.3556)
		(layer "F.Cu")
		(net "GND")
	)
	(segment
		(start 304.122582 -275.516594)
		(end 305.443382 -275.516594)
		(width 0.381)
		(layer "F.Cu")
		(net "GND")
	)
	(segment
		(start 293.799514 -229.616762)
		(end 292.694614 -229.616762)
		(width 0.381)
		(layer "F.Cu")
		(net "GND")
	)
	(segment
		(start 31.307278 -138.41984)
		(end 31.325058 -138.43762)
		(width 0.3556)
		(layer "F.Cu")
		(net "GND")
	)
	(segment
		(start 372.377716 -264.499852)
		(end 372.377462 -264.500106)
		(width 0.2032)
		(layer "F.Cu")
		(net "GND")
	)
	(segment
		(start 267.724382 -228.766624)
		(end 268.829282 -228.766624)
		(width 0.381)
		(layer "F.Cu")
		(net "GND")
	)
	(segment
		(start 384.136646 -271.834356)
		(end 384.125216 -271.825212)
		(width 0.254)
		(layer "F.Cu")
		(net "GND")
	)
	(segment
		(start 421.840914 -281.466798)
		(end 420.736014 -281.466798)
		(width 0.381)
		(layer "F.Cu")
		(net "GND")
	)
	(segment
		(start 312.987182 -262.76681)
		(end 314.092082 -262.76681)
		(width 0.381)
		(layer "F.Cu")
		(net "GND")
	)
	(segment
		(start 54.724046 -220.266768)
		(end 53.403246 -220.266768)
		(width 0.381)
		(layer "F.Cu")
		(net "GND")
	)
	(segment
		(start 38.45687 -7.215124)
		(end 38.45687 -8.320024)
		(width 0.3556)
		(layer "F.Cu")
		(net "GND")
	)
	(segment
		(start 337.299808 -46.449996)
		(end 337.699858 -46.850046)
		(width 0.2032)
		(layer "F.Cu")
		(net "GND")
	)
	(segment
		(start 18.679414 -233.86669)
		(end 19.784314 -233.86669)
		(width 0.381)
		(layer "F.Cu")
		(net "GND")
	)
	(segment
		(start 345.554554 -48.950372)
		(end 345.026234 -47.949612)
		(width 0.1778)
		(layer "F.Cu")
		(net "GND")
	)
	(segment
		(start 328.395584 -38.880288)
		(end 327.41489 -38.945566)
		(width 0.2032)
		(layer "F.Cu")
		(net "GND")
	)
	(segment
		(start 184.439814 -239.81664)
		(end 185.544714 -239.81664)
		(width 0.381)
		(layer "F.Cu")
		(net "GND")
	)
	(segment
		(start 104.701848 -284.033468)
		(end 104.701594 -284.033722)
		(width 0.254)
		(layer "F.Cu")
		(net "GND")
	)
	(segment
		(start 406.753314 -287.416748)
		(end 407.858214 -287.416748)
		(width 0.381)
		(layer "F.Cu")
		(net "GND")
	)
	(segment
		(start 441.028582 -228.766624)
		(end 442.133482 -228.766624)
		(width 0.381)
		(layer "F.Cu")
		(net "GND")
	)
	(segment
		(start 444.472314 -268.71676)
		(end 443.367414 -268.71676)
		(width 0.381)
		(layer "F.Cu")
		(net "GND")
	)
	(segment
		(start 453.121014 -227.066602)
		(end 452.016114 -227.066602)
		(width 0.381)
		(layer "F.Cu")
		(net "GND")
	)
	(segment
		(start 162.913314 -267.866622)
		(end 164.018214 -267.866622)
		(width 0.381)
		(layer "F.Cu")
		(net "GND")
	)
	(segment
		(start 343.819734 -54.558692)
		(end 343.81948 -54.558946)
		(width 0.2032)
		(layer "F.Cu")
		(net "GND")
	)
	(segment
		(start 439.923682 -264.466578)
		(end 441.028582 -264.466578)
		(width 0.381)
		(layer "F.Cu")
		(net "GND")
	)
	(segment
		(start 372.377716 -255.825498)
		(end 372.377716 -256.361184)
		(width 0.254)
		(layer "F.Cu")
		(net "GND")
	)
	(segment
		(start 429.384714 -295.06672)
		(end 430.489614 -295.06672)
		(width 0.381)
		(layer "F.Cu")
		(net "GND")
	)
	(segment
		(start 297.899582 -247.466612)
		(end 299.004482 -247.466612)
		(width 0.381)
		(layer "F.Cu")
		(net "GND")
	)
	(segment
		(start 332.397608 -39.443152)
		(end 332.897734 -39.295324)
		(width 0.2032)
		(layer "F.Cu")
		(net "GND")
	)
	(segment
		(start 453.121014 -300.166786)
		(end 452.016114 -300.166786)
		(width 0.381)
		(layer "F.Cu")
		(net "GND")
	)
	(segment
		(start 412.585662 -364.963964)
		(end 413.019748 -364.529878)
		(width 0.2032)
		(layer "F.Cu")
		(net "GND")
	)
	(segment
		(start 26.223214 -267.866622)
		(end 27.328114 -267.866622)
		(width 0.381)
		(layer "F.Cu")
		(net "GND")
	)
	(segment
		(start 179.105814 -194.766692)
		(end 178.000914 -194.766692)
		(width 0.381)
		(layer "F.Cu")
		(net "GND")
	)
	(segment
		(start 267.724382 -297.616626)
		(end 268.829282 -297.616626)
		(width 0.381)
		(layer "F.Cu")
		(net "GND")
	)
	(segment
		(start 301.343314 -296.766742)
		(end 302.448214 -296.766742)
		(width 0.381)
		(layer "F.Cu")
		(net "GND")
	)
	(segment
		(start 377.076716 -284.033468)
		(end 377.076462 -284.033722)
		(width 0.254)
		(layer "F.Cu")
		(net "GND")
	)
	(segment
		(start 20.889214 -215.166702)
		(end 19.784314 -215.166702)
		(width 0.381)
		(layer "F.Cu")
		(net "GND")
	)
	(segment
		(start 96.133666 -238.761524)
		(end 96.133412 -238.76127)
		(width 0.2032)
		(layer "F.Cu")
		(net "GND")
	)
	(segment
		(start 210.514946 -301.866808)
		(end 211.619846 -301.866808)
		(width 0.381)
		(layer "F.Cu")
		(net "GND")
	)
	(segment
		(start 125.737366 -229.808532)
		(end 125.737366 -229.272846)
		(width 0.2032)
		(layer "F.Cu")
		(net "GND")
	)
	(segment
		(start 262.519414 -206.666592)
		(end 263.624314 -206.666592)
		(width 0.381)
		(layer "F.Cu")
		(net "GND")
	)
	(segment
		(start 338.074762 -282.683966)
		(end 338.074762 -283.219906)
		(width 0.254)
		(layer "F.Cu")
		(net "GND")
	)
	(segment
		(start 87.675466 -246.900446)
		(end 87.675466 -246.364506)
		(width 0.2032)
		(layer "F.Cu")
		(net "GND")
	)
	(segment
		(start 347.36278 -242.295172)
		(end 347.363034 -242.294918)
		(width 0.2032)
		(layer "F.Cu")
		(net "GND")
	)
	(segment
		(start 291.460682 -228.766624)
		(end 290.355782 -228.766624)
		(width 0.381)
		(layer "F.Cu")
		(net "GND")
	)
	(segment
		(start 123.497848 -284.033468)
		(end 123.497594 -284.033722)
		(width 0.254)
		(layer "F.Cu")
		(net "GND")
	)
	(segment
		(start 297.899582 -297.616626)
		(end 299.004482 -297.616626)
		(width 0.381)
		(layer "F.Cu")
		(net "GND")
	)
	(segment
		(start 52.298346 -265.316716)
		(end 53.403246 -265.316716)
		(width 0.381)
		(layer "F.Cu")
		(net "GND")
	)
	(segment
		(start 370.38788 -243.644674)
		(end 370.38788 -243.108988)
		(width 0.254)
		(layer "F.Cu")
		(net "GND")
	)
	(segment
		(start 59.842146 -301.866808)
		(end 60.947046 -301.866808)
		(width 0.381)
		(layer "F.Cu")
		(net "GND")
	)
	(segment
		(start 307.29555 -28.7528)
		(end 307.2384 -28.7528)
		(width 0.3556)
		(layer "F.Cu")
		(net "GND")
	)
	(segment
		(start 414.756854 -11.26998)
		(end 414.756854 -10.16508)
		(width 0.3556)
		(layer "F.Cu")
		(net "GND")
	)
	(segment
		(start 427.045882 -308.666642)
		(end 425.940982 -308.666642)
		(width 0.381)
		(layer "F.Cu")
		(net "GND")
	)
	(segment
		(start 218.48953 -127.803148)
		(end 219.10548 -127.803148)
		(width 0.3556)
		(layer "F.Cu")
		(net "GND")
	)
	(segment
		(start 456.116182 -308.666642)
		(end 455.011282 -308.666642)
		(width 0.381)
		(layer "F.Cu")
		(net "GND")
	)
	(segment
		(start 335.67878 -52.679346)
		(end 335.138268 -52.679346)
		(width 0.2032)
		(layer "F.Cu")
		(net "GND")
	)
	(segment
		(start 435.823614 -276.366732)
		(end 436.928514 -276.366732)
		(width 0.381)
		(layer "F.Cu")
		(net "GND")
	)
	(segment
		(start 110.340648 -261.244842)
		(end 110.340394 -261.245096)
		(width 0.254)
		(layer "F.Cu")
		(net "GND")
	)
	(segment
		(start 347.36278 -226.017582)
		(end 347.363034 -226.017328)
		(width 0.254)
		(layer "F.Cu")
		(net "GND")
	)
	(segment
		(start 29.666946 -306.116736)
		(end 30.771846 -306.116736)
		(width 0.381)
		(layer "F.Cu")
		(net "GND")
	)
	(segment
		(start 190.01359 -68.407788)
		(end 189.40399 -68.407788)
		(width 0.3556)
		(layer "F.Cu")
		(net "GND")
	)
	(segment
		(start 187.883546 -227.066602)
		(end 188.988446 -227.066602)
		(width 0.381)
		(layer "F.Cu")
		(net "GND")
	)
	(segment
		(start 100.472494 -282.683966)
		(end 100.472494 -283.219906)
		(width 0.254)
		(layer "F.Cu")
		(net "GND")
	)
	(segment
		(start 343.713562 -279.96388)
		(end 343.713816 -279.964134)
		(width 0.254)
		(layer "F.Cu")
		(net "GND")
	)
	(segment
		(start 312.987182 -207.51673)
		(end 314.307982 -207.51673)
		(width 0.381)
		(layer "F.Cu")
		(net "GND")
	)
	(segment
		(start 27.328114 -266.1666)
		(end 28.433014 -266.1666)
		(width 0.381)
		(layer "F.Cu")
		(net "GND")
	)
	(segment
		(start 185.544714 -204.116686)
		(end 184.439814 -204.116686)
		(width 0.381)
		(layer "F.Cu")
		(net "GND")
	)
	(segment
		(start 89.194894 -282.683966)
		(end 89.194894 -283.219906)
		(width 0.2032)
		(layer "F.Cu")
		(net "GND")
	)
	(segment
		(start 457.221082 -278.916638)
		(end 456.116182 -278.916638)
		(width 0.381)
		(layer "F.Cu")
		(net "GND")
	)
	(segment
		(start 46.697138 -335.477612)
		(end 47.637446 -335.477612)
		(width 0.508)
		(layer "F.Cu")
		(net "GND")
	)
	(segment
		(start 419.502082 -204.116686)
		(end 418.397182 -204.116686)
		(width 0.381)
		(layer "F.Cu")
		(net "GND")
	)
	(segment
		(start 366.04575 -15.255748)
		(end 366.04575 -14.569948)
		(width 0.3556)
		(layer "F.Cu")
		(net "GND")
	)
	(segment
		(start 349.352362 -272.917158)
		(end 349.352362 -273.453098)
		(width 0.2032)
		(layer "F.Cu")
		(net "GND")
	)
	(segment
		(start 126.207266 -246.900446)
		(end 126.207012 -246.900192)
		(width 0.2032)
		(layer "F.Cu")
		(net "GND")
	)
	(segment
		(start 305.443382 -306.96662)
		(end 306.548282 -306.96662)
		(width 0.381)
		(layer "F.Cu")
		(net "GND")
	)
	(segment
		(start 200.632314 -308.666642)
		(end 201.737214 -308.666642)
		(width 0.381)
		(layer "F.Cu")
		(net "GND")
	)
	(segment
		(start 263.624314 -208.366614)
		(end 264.729214 -208.366614)
		(width 0.381)
		(layer "F.Cu")
		(net "GND")
	)
	(segment
		(start 119.268748 -281.056334)
		(end 119.268748 -281.59202)
		(width 0.254)
		(layer "F.Cu")
		(net "GND")
	)
	(segment
		(start 342.773762 -289.195002)
		(end 342.773762 -289.807142)
		(width 0.2032)
		(layer "F.Cu")
		(net "GND")
	)
	(segment
		(start 59.842146 -279.766776)
		(end 60.947046 -279.766776)
		(width 0.381)
		(layer "F.Cu")
		(net "GND")
	)
	(segment
		(start 86.375494 -256.639314)
		(end 86.845394 -256.361438)
		(width 0.254)
		(layer "F.Cu")
		(net "GND")
	)
	(segment
		(start 418.408866 -173.919642)
		(end 418.180012 -173.919642)
		(width 0.2032)
		(layer "F.Cu")
		(net "GND")
	)
	(segment
		(start 462.555082 -247.466612)
		(end 463.659982 -247.466612)
		(width 0.381)
		(layer "F.Cu")
		(net "GND")
	)
	(segment
		(start 193.088514 -226.216718)
		(end 191.983614 -226.216718)
		(width 0.381)
		(layer "F.Cu")
		(net "GND")
	)
	(segment
		(start 94.363794 -265.592306)
		(end 94.364048 -265.592306)
		(width 0.254)
		(layer "F.Cu")
		(net "GND")
	)
	(segment
		(start 34.871914 -295.916604)
		(end 33.767014 -295.916604)
		(width 0.381)
		(layer "F.Cu")
		(net "GND")
	)
	(segment
		(start 56.398414 -262.76681)
		(end 57.503314 -262.76681)
		(width 0.381)
		(layer "F.Cu")
		(net "GND")
	)
	(segment
		(start 134.195566 -223.297496)
		(end 134.195566 -222.761556)
		(width 0.254)
		(layer "F.Cu")
		(net "GND")
	)
	(segment
		(start 101.433884 -393.03579)
		(end 100.817934 -393.65174)
		(width 0.3556)
		(layer "F.Cu")
		(net "GND")
	)
	(segment
		(start 422.945814 -296.766742)
		(end 421.840914 -296.766742)
		(width 0.381)
		(layer "F.Cu")
		(net "GND")
	)
	(segment
		(start 49.959514 -232.166668)
		(end 51.064414 -232.166668)
		(width 0.381)
		(layer "F.Cu")
		(net "GND")
	)
	(segment
		(start 406.753314 -268.71676)
		(end 407.858214 -268.71676)
		(width 0.381)
		(layer "F.Cu")
		(net "GND")
	)
	(segment
		(start 161.808414 -308.666642)
		(end 162.913314 -308.666642)
		(width 0.381)
		(layer "F.Cu")
		(net "GND")
	)
	(segment
		(start 197.81393 -106.225848)
		(end 198.42353 -106.225848)
		(width 0.3556)
		(layer "F.Cu")
		(net "GND")
	)
	(segment
		(start 385.424934 -220.855794)
		(end 385.424934 -220.319854)
		(width 0.2032)
		(layer "F.Cu")
		(net "GND")
	)
	(segment
		(start 293.799514 -309.51678)
		(end 292.694614 -309.51678)
		(width 0.381)
		(layer "F.Cu")
		(net "GND")
	)
	(segment
		(start 215.719914 -228.766624)
		(end 216.824814 -228.766624)
		(width 0.381)
		(layer "F.Cu")
		(net "GND")
	)
	(segment
		(start 199.527414 -288.266632)
		(end 200.632314 -288.266632)
		(width 0.381)
		(layer "F.Cu")
		(net "GND")
	)
	(segment
		(start 99.063048 -257.45313)
		(end 99.063048 -257.98907)
		(width 0.2032)
		(layer "F.Cu")
		(net "GND")
	)
	(segment
		(start 101.302312 -236.319822)
		(end 101.302566 -236.319568)
		(width 0.2032)
		(layer "F.Cu")
		(net "GND")
	)
	(segment
		(start 101.302566 -246.086376)
		(end 101.302566 -245.55069)
		(width 0.2032)
		(layer "F.Cu")
		(net "GND")
	)
	(segment
		(start 59.626246 -273.816572)
		(end 60.947046 -273.816572)
		(width 0.381)
		(layer "F.Cu")
		(net "GND")
	)
	(segment
		(start 170.457114 -264.466578)
		(end 171.562014 -264.466578)
		(width 0.381)
		(layer "F.Cu")
		(net "GND")
	)
	(segment
		(start 256.080514 -217.716608)
		(end 257.185414 -217.716608)
		(width 0.381)
		(layer "F.Cu")
		(net "GND")
	)
	(segment
		(start 104.701848 -277.521924)
		(end 104.701594 -277.522178)
		(width 0.2032)
		(layer "F.Cu")
		(net "GND")
	)
	(segment
		(start 374.14708 -246.900192)
		(end 374.14708 -246.364506)
		(width 0.2032)
		(layer "F.Cu")
		(net "GND")
	)
	(segment
		(start 334.315562 -263.150604)
		(end 335.255362 -263.686544)
		(width 0.254)
		(layer "F.Cu")
		(net "GND")
	)
	(segment
		(start 102.242112 -226.017582)
		(end 102.242366 -226.017328)
		(width 0.254)
		(layer "F.Cu")
		(net "GND")
	)
	(segment
		(start 302.923702 -435.585108)
		(end 303.281842 -435.585108)
		(width 0.3556)
		(layer "F.Cu")
		(net "GND")
	)
	(segment
		(start 113.050066 -215.436958)
		(end 113.049812 -215.436704)
		(width 0.2032)
		(layer "F.Cu")
		(net "GND")
	)
	(segment
		(start 358.170734 -250.155964)
		(end 358.170734 -249.620024)
		(width 0.254)
		(layer "F.Cu")
		(net "GND")
	)
	(segment
		(start 122.917712 -216.250774)
		(end 122.917966 -216.25052)
		(width 0.254)
		(layer "F.Cu")
		(net "GND")
	)
	(segment
		(start 304.09896 -430.25822)
		(end 304.09896 -429.621188)
		(width 0.3556)
		(layer "F.Cu")
		(net "GND")
	)
	(segment
		(start 184.439814 -216.866724)
		(end 185.544714 -216.866724)
		(width 0.381)
		(layer "F.Cu")
		(net "GND")
	)
	(segment
		(start 419.502082 -232.166668)
		(end 418.397182 -232.166668)
		(width 0.381)
		(layer "F.Cu")
		(net "GND")
	)
	(segment
		(start 108.351066 -227.367084)
		(end 108.351066 -226.831144)
		(width 0.2032)
		(layer "F.Cu")
		(net "GND")
	)
	(segment
		(start 200.632314 -239.81664)
		(end 201.737214 -239.81664)
		(width 0.381)
		(layer "F.Cu")
		(net "GND")
	)
	(segment
		(start 164.262562 -238.116618)
		(end 162.913314 -238.116618)
		(width 0.381)
		(layer "F.Cu")
		(net "GND")
	)
	(segment
		(start 370.85778 -220.041978)
		(end 370.858034 -220.041724)
		(width 0.254)
		(layer "F.Cu")
		(net "GND")
	)
	(segment
		(start 197.637146 -220.266768)
		(end 196.532246 -220.266768)
		(width 0.381)
		(layer "F.Cu")
		(net "GND")
	)
	(segment
		(start 360.51998 -226.553268)
		(end 360.51998 -226.017582)
		(width 0.254)
		(layer "F.Cu")
		(net "GND")
	)
	(segment
		(start 457.221082 -194.766692)
		(end 456.116182 -194.766692)
		(width 0.381)
		(layer "F.Cu")
		(net "GND")
	)
	(segment
		(start 334.898746 -39.295324)
		(end 335.399126 -39.443152)
		(width 0.2032)
		(layer "F.Cu")
		(net "GND")
	)
	(segment
		(start 211.619846 -248.31675)
		(end 212.724746 -248.31675)
		(width 0.381)
		(layer "F.Cu")
		(net "GND")
	)
	(segment
		(start 109.870494 -266.405868)
		(end 109.870494 -266.941808)
		(width 0.254)
		(layer "F.Cu")
		(net "GND")
	)
	(segment
		(start 368.03838 -216.78646)
		(end 368.03838 -216.250774)
		(width 0.254)
		(layer "F.Cu")
		(net "GND")
	)
	(segment
		(start 117.53088 -102.193598)
		(end 117.53088 -102.809548)
		(width 0.3556)
		(layer "F.Cu")
		(net "GND")
	)
	(segment
		(start 296.794682 -232.166668)
		(end 297.899582 -232.166668)
		(width 0.381)
		(layer "F.Cu")
		(net "GND")
	)
	(segment
		(start 202.971146 -309.51678)
		(end 204.076046 -309.51678)
		(width 0.381)
		(layer "F.Cu")
		(net "GND")
	)
	(segment
		(start 260.180582 -245.76659)
		(end 259.075682 -245.76659)
		(width 0.381)
		(layer "F.Cu")
		(net "GND")
	)
	(segment
		(start 208.176114 -235.566712)
		(end 209.281014 -235.566712)
		(width 0.381)
		(layer "F.Cu")
		(net "GND")
	)
	(segment
		(start 172.795946 -267.016738)
		(end 173.900846 -267.016738)
		(width 0.381)
		(layer "F.Cu")
		(net "GND")
	)
	(segment
		(start 104.231694 -273.452844)
		(end 104.231948 -273.453098)
		(width 0.2032)
		(layer "F.Cu")
		(net "GND")
	)
	(segment
		(start 85.905594 -257.45313)
		(end 85.905594 -257.98907)
		(width 0.254)
		(layer "F.Cu")
		(net "GND")
	)
	(segment
		(start 101.882448 -272.103342)
		(end 101.882448 -272.639028)
		(width 0.2032)
		(layer "F.Cu")
		(net "GND")
	)
	(segment
		(start 153.99004 -41.059608)
		(end 153.99004 -41.439338)
		(width 0.3556)
		(layer "F.Cu")
		(net "GND")
	)
	(segment
		(start 405.326596 -204.96657)
		(end 406.753314 -204.96657)
		(width 0.381)
		(layer "F.Cu")
		(net "GND")
	)
	(segment
		(start 208.176114 -207.51673)
		(end 209.281014 -207.51673)
		(width 0.381)
		(layer "F.Cu")
		(net "GND")
	)
	(segment
		(start 95.303848 -284.033468)
		(end 95.303594 -284.033722)
		(width 0.254)
		(layer "F.Cu")
		(net "GND")
	)
	(segment
		(start 133.365494 -274.54479)
		(end 133.365494 -275.08073)
		(width 0.2032)
		(layer "F.Cu")
		(net "GND")
	)
	(segment
		(start 354.991162 -277.800562)
		(end 354.991162 -278.336248)
		(width 0.254)
		(layer "F.Cu")
		(net "GND")
	)
	(segment
		(start 190.093346 -199.01662)
		(end 188.988446 -199.01662)
		(width 0.381)
		(layer "F.Cu")
		(net "GND")
	)
	(segment
		(start 123.387866 -235.506006)
		(end 123.387612 -235.505752)
		(width 0.2032)
		(layer "F.Cu")
		(net "GND")
	)
	(segment
		(start 452.016114 -203.266802)
		(end 450.911214 -203.266802)
		(width 0.381)
		(layer "F.Cu")
		(net "GND")
	)
	(segment
		(start 347.942916 -286.7533)
		(end 347.942916 -287.288986)
		(width 0.254)
		(layer "F.Cu")
		(net "GND")
	)
	(segment
		(start 254.975614 -208.366614)
		(end 256.080514 -208.366614)
		(width 0.381)
		(layer "F.Cu")
		(net "GND")
	)
	(segment
		(start 354.88118 -216.78646)
		(end 354.88118 -216.250774)
		(width 0.254)
		(layer "F.Cu")
		(net "GND")
	)
	(segment
		(start 188.988446 -268.71676)
		(end 187.883546 -268.71676)
		(width 0.381)
		(layer "F.Cu")
		(net "GND")
	)
	(segment
		(start 370.498116 -254.733298)
		(end 370.497862 -254.733552)
		(width 0.254)
		(layer "F.Cu")
		(net "GND")
	)
	(segment
		(start 158.813246 -240.666778)
		(end 159.918146 -240.666778)
		(width 0.381)
		(layer "F.Cu")
		(net "GND")
	)
	(segment
		(start 308.887114 -204.96657)
		(end 309.992014 -204.96657)
		(width 0.381)
		(layer "F.Cu")
		(net "GND")
	)
	(segment
		(start 124.437648 -257.45313)
		(end 124.437394 -257.98907)
		(width 0.2032)
		(layer "F.Cu")
		(net "GND")
	)
	(segment
		(start 254.975614 -300.166786)
		(end 256.080514 -300.166786)
		(width 0.381)
		(layer "F.Cu")
		(net "GND")
	)
	(segment
		(start 416.484562 -173.515274)
		(end 416.056318 -173.943518)
		(width 0.2032)
		(layer "F.Cu")
		(net "GND")
	)
	(segment
		(start 443.367414 -272.116804)
		(end 444.472314 -272.116804)
		(width 0.381)
		(layer "F.Cu")
		(net "GND")
	)
	(segment
		(start 7.035546 -217.716608)
		(end 8.140446 -217.716608)
		(width 0.381)
		(layer "F.Cu")
		(net "GND")
	)
	(segment
		(start 432.379882 -244.066568)
		(end 433.484782 -244.066568)
		(width 0.381)
		(layer "F.Cu")
		(net "GND")
	)
	(segment
		(start 345.123516 -286.7533)
		(end 345.123516 -287.288986)
		(width 0.254)
		(layer "F.Cu")
		(net "GND")
	)
	(segment
		(start 44.569634 -108.047282)
		(end 45.179234 -108.047282)
		(width 0.3556)
		(layer "F.Cu")
		(net "GND")
	)
	(segment
		(start 382.165352 -345.793314)
		(end 382.642364 -345.316302)
		(width 0.2032)
		(layer "F.Cu")
		(net "GND")
	)
	(segment
		(start 194.193414 -205.816708)
		(end 193.088514 -205.816708)
		(width 0.381)
		(layer "F.Cu")
		(net "GND")
	)
	(segment
		(start 122.558048 -261.244588)
		(end 122.557794 -261.244842)
		(width 0.2032)
		(layer "F.Cu")
		(net "GND")
	)
	(segment
		(start 110.625128 -334.191102)
		(end 110.197138 -333.763112)
		(width 0.2032)
		(layer "F.Cu")
		(net "GND")
	)
	(segment
		(start 462.48701 -40.352472)
		(end 463.171032 -40.352472)
		(width 0.3556)
		(layer "F.Cu")
		(net "GND")
	)
	(segment
		(start 275.268182 -215.166702)
		(end 274.163282 -215.166702)
		(width 0.381)
		(layer "F.Cu")
		(net "GND")
	)
	(segment
		(start 175.005746 -199.01662)
		(end 173.900846 -199.01662)
		(width 0.381)
		(layer "F.Cu")
		(net "GND")
	)
	(segment
		(start 19.784314 -213.46668)
		(end 18.679414 -213.46668)
		(width 0.381)
		(layer "F.Cu")
		(net "GND")
	)
	(segment
		(start 332.904592 -276.172676)
		(end 333.375762 -276.172676)
		(width 0.2032)
		(layer "F.Cu")
		(net "GND")
	)
	(segment
		(start 60.947046 -304.416714)
		(end 62.051946 -304.416714)
		(width 0.381)
		(layer "F.Cu")
		(net "GND")
	)
	(segment
		(start 44.754546 -260.21665)
		(end 45.859446 -260.21665)
		(width 0.381)
		(layer "F.Cu")
		(net "GND")
	)
	(segment
		(start 383.655062 -255.825498)
		(end 383.655062 -256.361438)
		(width 0.2032)
		(layer "F.Cu")
		(net "GND")
	)
	(segment
		(start 204.076046 -296.766742)
		(end 205.180946 -296.766742)
		(width 0.381)
		(layer "F.Cu")
		(net "GND")
	)
	(segment
		(start 420.736014 -240.666778)
		(end 421.840914 -240.666778)
		(width 0.381)
		(layer "F.Cu")
		(net "GND")
	)
	(segment
		(start 172.795946 -306.116736)
		(end 173.900846 -306.116736)
		(width 0.381)
		(layer "F.Cu")
		(net "GND")
	)
	(segment
		(start 94.723712 -236.319822)
		(end 94.723966 -236.319568)
		(width 0.2032)
		(layer "F.Cu")
		(net "GND")
	)
	(segment
		(start 124.437648 -275.35886)
		(end 124.437394 -275.8948)
		(width 0.2032)
		(layer "F.Cu")
		(net "GND")
	)
	(segment
		(start 124.327412 -240.388902)
		(end 124.327412 -239.853216)
		(width 0.2032)
		(layer "F.Cu")
		(net "GND")
	)
	(segment
		(start 413.192214 -283.166566)
		(end 414.297114 -283.166566)
		(width 0.381)
		(layer "F.Cu")
		(net "GND")
	)
	(segment
		(start 91.904312 -242.295172)
		(end 91.904566 -242.294918)
		(width 0.2032)
		(layer "F.Cu")
		(net "GND")
	)
	(segment
		(start 282.811982 -275.516594)
		(end 283.916882 -275.516594)
		(width 0.381)
		(layer "F.Cu")
		(net "GND")
	)
	(segment
		(start 410.853382 -207.51673)
		(end 409.748482 -207.51673)
		(width 0.381)
		(layer "F.Cu")
		(net "GND")
	)
	(segment
		(start 96.713294 -281.591766)
		(end 96.713548 -281.59202)
		(width 0.254)
		(layer "F.Cu")
		(net "GND")
	)
	(segment
		(start 425.940982 -305.266598)
		(end 424.836082 -305.266598)
		(width 0.381)
		(layer "F.Cu")
		(net "GND")
	)
	(segment
		(start 427.045882 -280.61666)
		(end 425.940982 -280.61666)
		(width 0.381)
		(layer "F.Cu")
		(net "GND")
	)
	(segment
		(start 261.285482 -245.76659)
		(end 260.180582 -245.76659)
		(width 0.381)
		(layer "F.Cu")
		(net "GND")
	)
	(segment
		(start 261.285482 -239.81664)
		(end 260.180582 -239.81664)
		(width 0.381)
		(layer "F.Cu")
		(net "GND")
	)
	(segment
		(start 421.15359 -180.349144)
		(end 421.15359 -179.707794)
		(width 0.381)
		(layer "F.Cu")
		(net "GND")
	)
	(segment
		(start 53.403246 -278.066754)
		(end 54.508146 -278.066754)
		(width 0.381)
		(layer "F.Cu")
		(net "GND")
	)
	(segment
		(start 65.047114 -301.01667)
		(end 66.152014 -301.01667)
		(width 0.381)
		(layer "F.Cu")
		(net "GND")
	)
	(segment
		(start 448.572382 -266.1666)
		(end 447.467482 -266.1666)
		(width 0.381)
		(layer "F.Cu")
		(net "GND")
	)
	(segment
		(start 162.913314 -216.866724)
		(end 161.73577 -216.866724)
		(width 0.381)
		(layer "F.Cu")
		(net "GND")
	)
	(segment
		(start 380.835916 -284.033468)
		(end 380.835662 -284.033722)
		(width 0.254)
		(layer "F.Cu")
		(net "GND")
	)
	(segment
		(start 176.896014 -289.966654)
		(end 178.000914 -289.966654)
		(width 0.381)
		(layer "F.Cu")
		(net "GND")
	)
	(segment
		(start 19.784314 -275.516594)
		(end 20.889214 -275.516594)
		(width 0.381)
		(layer "F.Cu")
		(net "GND")
	)
	(segment
		(start 29.666946 -278.066754)
		(end 30.771846 -278.066754)
		(width 0.381)
		(layer "F.Cu")
		(net "GND")
	)
	(segment
		(start 37.990272 -356.42423)
		(end 38.424358 -355.990144)
		(width 0.2032)
		(layer "F.Cu")
		(net "GND")
	)
	(segment
		(start 373.677434 -231.436164)
		(end 373.677434 -230.900478)
		(width 0.2032)
		(layer "F.Cu")
		(net "GND")
	)
	(segment
		(start 178.000914 -226.216718)
		(end 176.896014 -226.216718)
		(width 0.381)
		(layer "F.Cu")
		(net "GND")
	)
	(segment
		(start 202.971146 -221.96679)
		(end 204.076046 -221.96679)
		(width 0.381)
		(layer "F.Cu")
		(net "GND")
	)
	(segment
		(start 359.58018 -220.041978)
		(end 359.580434 -220.041724)
		(width 0.254)
		(layer "F.Cu")
		(net "GND")
	)
	(segment
		(start 405.648414 -234.716574)
		(end 406.753314 -234.716574)
		(width 0.381)
		(layer "F.Cu")
		(net "GND")
	)
	(segment
		(start 433.484782 -305.266598)
		(end 434.589682 -305.266598)
		(width 0.381)
		(layer "F.Cu")
		(net "GND")
	)
	(segment
		(start 453.121014 -304.416714)
		(end 452.016114 -304.416714)
		(width 0.381)
		(layer "F.Cu")
		(net "GND")
	)
	(segment
		(start 215.719914 -310.366664)
		(end 216.824814 -310.366664)
		(width 0.381)
		(layer "F.Cu")
		(net "GND")
	)
	(segment
		(start 422.66616 -144.075658)
		(end 422.66616 -144.689068)
		(width 0.3556)
		(layer "F.Cu")
		(net "GND")
	)
	(segment
		(start 190.093346 -231.316784)
		(end 188.988446 -231.316784)
		(width 0.381)
		(layer "F.Cu")
		(net "GND")
	)
	(segment
		(start 384.485134 -220.855794)
		(end 384.485134 -220.319854)
		(width 0.2032)
		(layer "F.Cu")
		(net "GND")
	)
	(segment
		(start 263.624314 -238.966756)
		(end 264.729214 -238.966756)
		(width 0.381)
		(layer "F.Cu")
		(net "GND")
	)
	(segment
		(start 208.176114 -204.116686)
		(end 209.281014 -204.116686)
		(width 0.381)
		(layer "F.Cu")
		(net "GND")
	)
	(segment
		(start 53.403246 -270.416782)
		(end 54.508146 -270.416782)
		(width 0.381)
		(layer "F.Cu")
		(net "GND")
	)
	(segment
		(start 158.813246 -212.616796)
		(end 159.918146 -212.616796)
		(width 0.381)
		(layer "F.Cu")
		(net "GND")
	)
	(segment
		(start 335.725262 -254.197612)
		(end 335.725262 -254.733552)
		(width 0.2032)
		(layer "F.Cu")
		(net "GND")
	)
	(segment
		(start 285.150814 -279.766776)
		(end 286.255714 -279.766776)
		(width 0.381)
		(layer "F.Cu")
		(net "GND")
	)
	(segment
		(start 52.298346 -244.916706)
		(end 53.403246 -244.916706)
		(width 0.381)
		(layer "F.Cu")
		(net "GND")
	)
	(segment
		(start 385.093464 -273.475958)
		(end 385.070604 -273.453098)
		(width 0.254)
		(layer "F.Cu")
		(net "GND")
	)
	(segment
		(start 195.427346 -250.016772)
		(end 196.532246 -250.016772)
		(width 0.381)
		(layer "F.Cu")
		(net "GND")
	)
	(segment
		(start 211.619846 -240.666778)
		(end 212.724746 -240.666778)
		(width 0.381)
		(layer "F.Cu")
		(net "GND")
	)
	(segment
		(start 109.620812 -338.47024)
		(end 109.40542 -338.254848)
		(width 0.381)
		(layer "F.Cu")
		(net "GND")
	)
	(segment
		(start 91.074494 -253.919482)
		(end 91.074748 -253.919736)
		(width 0.2032)
		(layer "F.Cu")
		(net "GND")
	)
	(segment
		(start 112.579912 -229.808786)
		(end 112.580166 -229.808532)
		(width 0.2032)
		(layer "F.Cu")
		(net "GND")
	)
	(segment
		(start 344.903552 -57.605168)
		(end 343.903046 -57.605168)
		(width 0.2032)
		(layer "F.Cu")
		(net "GND")
	)
	(segment
		(start 439.923682 -299.316648)
		(end 441.028582 -299.316648)
		(width 0.381)
		(layer "F.Cu")
		(net "GND")
	)
	(segment
		(start 96.106488 -338.86013)
		(end 96.733868 -338.86013)
		(width 0.381)
		(layer "F.Cu")
		(net "GND")
	)
	(segment
		(start 172.795946 -304.416714)
		(end 173.900846 -304.416714)
		(width 0.381)
		(layer "F.Cu")
		(net "GND")
	)
	(segment
		(start 169.352214 -266.1666)
		(end 170.457114 -266.1666)
		(width 0.381)
		(layer "F.Cu")
		(net "GND")
	)
	(segment
		(start 152.489154 -118.051072)
		(end 152.489154 -117.312948)
		(width 0.3556)
		(layer "F.Cu")
		(net "GND")
	)
	(segment
		(start 193.088514 -297.616626)
		(end 194.193414 -297.616626)
		(width 0.381)
		(layer "F.Cu")
		(net "GND")
	)
	(segment
		(start 453.121014 -221.96679)
		(end 452.016114 -221.96679)
		(width 0.381)
		(layer "F.Cu")
		(net "GND")
	)
	(segment
		(start 166.357046 -221.96679)
		(end 167.461946 -221.96679)
		(width 0.381)
		(layer "F.Cu")
		(net "GND")
	)
	(segment
		(start 139.004294 -261.522718)
		(end 139.944094 -262.058658)
		(width 0.254)
		(layer "F.Cu")
		(net "GND")
	)
	(segment
		(start 425.940982 -282.316682)
		(end 424.836082 -282.316682)
		(width 0.381)
		(layer "F.Cu")
		(net "GND")
	)
	(segment
		(start 342.824816 -36.92779)
		(end 342.824816 -37.08273)
		(width 0.2032)
		(layer "F.Cu")
		(net "GND")
	)
	(segment
		(start 57.503314 -314.616592)
		(end 58.824114 -314.616592)
		(width 0.381)
		(layer "F.Cu")
		(net "GND")
	)
	(segment
		(start 416.484562 -173.221904)
		(end 416.484562 -173.515274)
		(width 0.2032)
		(layer "F.Cu")
		(net "GND")
	)
	(segment
		(start 459.559914 -261.916672)
		(end 458.455014 -261.916672)
		(width 0.381)
		(layer "F.Cu")
		(net "GND")
	)
	(segment
		(start 88.145366 -218.414346)
		(end 88.145366 -217.878406)
		(width 0.2032)
		(layer "F.Cu")
		(net "GND")
	)
	(segment
		(start 266.619482 -277.216616)
		(end 267.724382 -277.216616)
		(width 0.381)
		(layer "F.Cu")
		(net "GND")
	)
	(segment
		(start 210.514946 -268.71676)
		(end 211.619846 -268.71676)
		(width 0.381)
		(layer "F.Cu")
		(net "GND")
	)
	(segment
		(start 169.352214 -249.166634)
		(end 170.457114 -249.166634)
		(width 0.381)
		(layer "F.Cu")
		(net "GND")
	)
	(segment
		(start 384.788156 -260.38937)
		(end 384.565398 -260.307836)
		(width 0.088646)
		(layer "F.Cu")
		(net "GND")
	)
	(segment
		(start 274.163282 -303.566576)
		(end 275.268182 -303.566576)
		(width 0.381)
		(layer "F.Cu")
		(net "GND")
	)
	(segment
		(start 293.799514 -300.166786)
		(end 292.694614 -300.166786)
		(width 0.381)
		(layer "F.Cu")
		(net "GND")
	)
	(segment
		(start 277.607014 -212.616796)
		(end 278.711914 -212.616796)
		(width 0.381)
		(layer "F.Cu")
		(net "GND")
	)
	(segment
		(start 271.168114 -223.666558)
		(end 270.063214 -223.666558)
		(width 0.381)
		(layer "F.Cu")
		(net "GND")
	)
	(segment
		(start 208.176114 -303.566576)
		(end 209.281014 -303.566576)
		(width 0.381)
		(layer "F.Cu")
		(net "GND")
	)
	(segment
		(start 423.68216 -144.075658)
		(end 423.68216 -144.689068)
		(width 0.3556)
		(layer "F.Cu")
		(net "GND")
	)
	(segment
		(start 22.123146 -240.666778)
		(end 23.228046 -240.666778)
		(width 0.381)
		(layer "F.Cu")
		(net "GND")
	)
	(segment
		(start 94.253812 -233.877866)
		(end 94.253812 -233.34218)
		(width 0.2032)
		(layer "F.Cu")
		(net "GND")
	)
	(segment
		(start 178.000914 -262.76681)
		(end 176.896014 -262.76681)
		(width 0.381)
		(layer "F.Cu")
		(net "GND")
	)
	(segment
		(start 164.018214 -232.166668)
		(end 162.913314 -232.166668)
		(width 0.381)
		(layer "F.Cu")
		(net "GND")
	)
	(segment
		(start 27.328114 -297.616626)
		(end 28.433014 -297.616626)
		(width 0.381)
		(layer "F.Cu")
		(net "GND")
	)
	(segment
		(start 63.942214 -226.216718)
		(end 65.047114 -226.216718)
		(width 0.381)
		(layer "F.Cu")
		(net "GND")
	)
	(segment
		(start 448.572382 -316.316614)
		(end 447.467482 -316.316614)
		(width 0.381)
		(layer "F.Cu")
		(net "GND")
	)
	(segment
		(start 185.544714 -262.76681)
		(end 186.649614 -262.76681)
		(width 0.381)
		(layer "F.Cu")
		(net "GND")
	)
	(segment
		(start 103.181912 -223.297496)
		(end 103.181912 -222.76181)
		(width 0.254)
		(layer "F.Cu")
		(net "GND")
	)
	(segment
		(start 254.975614 -206.666592)
		(end 256.080514 -206.666592)
		(width 0.381)
		(layer "F.Cu")
		(net "GND")
	)
	(segment
		(start 285.150814 -214.316564)
		(end 286.255714 -214.316564)
		(width 0.381)
		(layer "F.Cu")
		(net "GND")
	)
	(segment
		(start 196.532246 -206.666592)
		(end 197.637146 -206.666592)
		(width 0.381)
		(layer "F.Cu")
		(net "GND")
	)
	(segment
		(start 7.035546 -234.716574)
		(end 8.140446 -234.716574)
		(width 0.381)
		(layer "F.Cu")
		(net "GND")
	)
	(segment
		(start 99.422712 -249.342148)
		(end 99.422966 -249.341894)
		(width 0.2032)
		(layer "F.Cu")
		(net "GND")
	)
	(segment
		(start 132.425694 -263.150604)
		(end 132.425694 -263.68629)
		(width 0.2032)
		(layer "F.Cu")
		(net "GND")
	)
	(segment
		(start 356.76078 -226.553268)
		(end 356.76078 -226.017582)
		(width 0.254)
		(layer "F.Cu")
		(net "GND")
	)
	(segment
		(start 35.976814 -271.266666)
		(end 34.871914 -271.266666)
		(width 0.381)
		(layer "F.Cu")
		(net "GND")
	)
	(segment
		(start 96.243648 -260.708902)
		(end 96.243648 -261.244588)
		(width 0.2032)
		(layer "F.Cu")
		(net "GND")
	)
	(segment
		(start 285.150814 -309.51678)
		(end 286.255714 -309.51678)
		(width 0.381)
		(layer "F.Cu")
		(net "GND")
	)
	(segment
		(start 60.947046 -195.616576)
		(end 62.051946 -195.616576)
		(width 0.381)
		(layer "F.Cu")
		(net "GND")
	)
	(segment
		(start 262.519414 -233.016806)
		(end 263.624314 -233.016806)
		(width 0.381)
		(layer "F.Cu")
		(net "GND")
	)
	(segment
		(start 166.357046 -250.016772)
		(end 167.461946 -250.016772)
		(width 0.381)
		(layer "F.Cu")
		(net "GND")
	)
	(segment
		(start 293.799514 -242.3668)
		(end 292.694614 -242.3668)
		(width 0.381)
		(layer "F.Cu")
		(net "GND")
	)
	(segment
		(start 303.900586 -425.03471)
		(end 303.875186 -425.00931)
		(width 0.3556)
		(layer "F.Cu")
		(net "GND")
	)
	(segment
		(start 178.000914 -301.01667)
		(end 179.105814 -301.01667)
		(width 0.381)
		(layer "F.Cu")
		(net "GND")
	)
	(segment
		(start 200.632314 -306.96662)
		(end 201.737214 -306.96662)
		(width 0.381)
		(layer "F.Cu")
		(net "GND")
	)
	(segment
		(start 211.99221 -26.468324)
		(end 211.99221 -22.443948)
		(width 0.3556)
		(layer "F.Cu")
		(net "GND")
	)
	(segment
		(start 339.014562 -261.522718)
		(end 339.014562 -262.058658)
		(width 0.2032)
		(layer "F.Cu")
		(net "GND")
	)
	(segment
		(start 452.016114 -263.616694)
		(end 450.911214 -263.616694)
		(width 0.381)
		(layer "F.Cu")
		(net "GND")
	)
	(segment
		(start 116.449094 -269.66164)
		(end 116.449348 -270.167862)
		(width 0.2032)
		(layer "F.Cu")
		(net "GND")
	)
	(segment
		(start 30.771846 -204.96657)
		(end 31.876746 -204.96657)
		(width 0.381)
		(layer "F.Cu")
		(net "GND")
	)
	(segment
		(start 211.619846 -289.11677)
		(end 210.514946 -289.11677)
		(width 0.381)
		(layer "F.Cu")
		(net "GND")
	)
	(segment
		(start 29.031692 -406.037288)
		(end 29.666692 -406.037288)
		(width 0.3556)
		(layer "F.Cu")
		(net "GND")
	)
	(segment
		(start 431.61331 -133.478778)
		(end 431.000154 -133.478778)
		(width 0.381)
		(layer "F.Cu")
		(net "GND")
	)
	(segment
		(start 113.629694 -287.567116)
		(end 113.629694 -288.103056)
		(width 0.254)
		(layer "F.Cu")
		(net "GND")
	)
	(segment
		(start 411.450028 -29.785818)
		(end 412.374334 -29.785818)
		(width 0.3556)
		(layer "F.Cu")
		(net "GND")
	)
	(segment
		(start 164.018214 -249.166634)
		(end 162.913314 -249.166634)
		(width 0.381)
		(layer "F.Cu")
		(net "GND")
	)
	(segment
		(start 355.461316 -283.497782)
		(end 355.461316 -284.033468)
		(width 0.254)
		(layer "F.Cu")
		(net "GND")
	)
	(segment
		(start 460.664814 -231.316784)
		(end 459.559914 -231.316784)
		(width 0.381)
		(layer "F.Cu")
		(net "GND")
	)
	(segment
		(start 43.85691 -7.215124)
		(end 43.85691 -8.320024)
		(width 0.3556)
		(layer "F.Cu")
		(net "GND")
	)
	(segment
		(start 188.988446 -216.016586)
		(end 187.883546 -216.016586)
		(width 0.381)
		(layer "F.Cu")
		(net "GND")
	)
	(segment
		(start 425.940982 -215.166702)
		(end 427.045882 -215.166702)
		(width 0.381)
		(layer "F.Cu")
		(net "GND")
	)
	(segment
		(start 441.028582 -232.166668)
		(end 442.133482 -232.166668)
		(width 0.381)
		(layer "F.Cu")
		(net "GND")
	)
	(segment
		(start 209.422492 -36.17214)
		(end 209.422492 -36.880292)
		(width 0.2286)
		(layer "F.Cu")
		(net "GND")
	)
	(segment
		(start 377.076462 -264.500106)
		(end 377.076462 -264.50036)
		(width 0.2032)
		(layer "F.Cu")
		(net "GND")
	)
	(segment
		(start 361.569762 -257.175254)
		(end 361.569762 -256.639314)
		(width 0.254)
		(layer "F.Cu")
		(net "GND")
	)
	(segment
		(start 334.099408 -49.650396)
		(end 334.499458 -49.250346)
		(width 0.2032)
		(layer "F.Cu")
		(net "GND")
	)
	(segment
		(start 352.323146 -353.86264)
		(end 352.089974 -354.095812)
		(width 0.381)
		(layer "F.Cu")
		(net "GND")
	)
	(segment
		(start 375.55678 -241.203226)
		(end 375.557034 -241.202972)
		(width 0.2032)
		(layer "F.Cu")
		(net "GND")
	)
	(segment
		(start 134.195566 -236.319822)
		(end 134.195566 -235.783882)
		(width 0.2032)
		(layer "F.Cu")
		(net "GND")
	)
	(segment
		(start 53.403246 -298.466764)
		(end 54.508146 -298.466764)
		(width 0.381)
		(layer "F.Cu")
		(net "GND")
	)
	(segment
		(start 260.180582 -277.216616)
		(end 259.075682 -277.216616)
		(width 0.381)
		(layer "F.Cu")
		(net "GND")
	)
	(segment
		(start 208.176114 -250.866656)
		(end 209.281014 -250.866656)
		(width 0.381)
		(layer "F.Cu")
		(net "GND")
	)
	(segment
		(start 305.443382 -216.866724)
		(end 306.548282 -216.866724)
		(width 0.381)
		(layer "F.Cu")
		(net "GND")
	)
	(segment
		(start 11.135614 -211.766658)
		(end 12.240514 -211.766658)
		(width 0.381)
		(layer "F.Cu")
		(net "GND")
	)
	(segment
		(start 173.900846 -315.46673)
		(end 172.795946 -315.46673)
		(width 0.381)
		(layer "F.Cu")
		(net "GND")
	)
	(segment
		(start 296.794682 -278.916638)
		(end 297.899582 -278.916638)
		(width 0.381)
		(layer "F.Cu")
		(net "GND")
	)
	(segment
		(start 49.959514 -239.81664)
		(end 51.064414 -239.81664)
		(width 0.381)
		(layer "F.Cu")
		(net "GND")
	)
	(segment
		(start 463.659982 -211.766658)
		(end 464.764882 -211.766658)
		(width 0.381)
		(layer "F.Cu")
		(net "GND")
	)
	(segment
		(start 448.572382 -222.816674)
		(end 447.467482 -222.816674)
		(width 0.381)
		(layer "F.Cu")
		(net "GND")
	)
	(segment
		(start 382.245362 -281.591512)
		(end 382.245616 -281.591766)
		(width 0.254)
		(layer "F.Cu")
		(net "GND")
	)
	(segment
		(start 107.051094 -281.591766)
		(end 107.051348 -281.59202)
		(width 0.254)
		(layer "F.Cu")
		(net "GND")
	)
	(segment
		(start 459.559914 -231.316784)
		(end 458.455014 -231.316784)
		(width 0.381)
		(layer "F.Cu")
		(net "GND")
	)
	(segment
		(start 262.519414 -234.716574)
		(end 263.624314 -234.716574)
		(width 0.381)
		(layer "F.Cu")
		(net "GND")
	)
	(segment
		(start 300.238414 -246.616728)
		(end 301.343314 -246.616728)
		(width 0.381)
		(layer "F.Cu")
		(net "GND")
	)
	(segment
		(start 126.207012 -242.016788)
		(end 126.207012 -241.481102)
		(width 0.2032)
		(layer "F.Cu")
		(net "GND")
	)
	(segment
		(start 52.298346 -307.816758)
		(end 53.403246 -307.816758)
		(width 0.381)
		(layer "F.Cu")
		(net "GND")
	)
	(segment
		(start 271.168114 -197.316598)
		(end 270.063214 -197.316598)
		(width 0.381)
		(layer "F.Cu")
		(net "GND")
	)
	(segment
		(start 386.83438 -231.436418)
		(end 387.304534 -231.714548)
		(width 0.254)
		(layer "F.Cu")
		(net "GND")
	)
	(segment
		(start 261.285482 -305.266598)
		(end 260.180582 -305.266598)
		(width 0.381)
		(layer "F.Cu")
		(net "GND")
	)
	(segment
		(start 93.783912 -226.017582)
		(end 93.784166 -226.017328)
		(width 0.254)
		(layer "F.Cu")
		(net "GND")
	)
	(segment
		(start 196.532246 -261.916672)
		(end 197.637146 -261.916672)
		(width 0.381)
		(layer "F.Cu")
		(net "GND")
	)
	(segment
		(start 169.352214 -250.866656)
		(end 170.457114 -250.866656)
		(width 0.381)
		(layer "F.Cu")
		(net "GND")
	)
	(segment
		(start 354.41128 -233.877866)
		(end 354.41128 -233.34218)
		(width 0.2032)
		(layer "F.Cu")
		(net "GND")
	)
	(segment
		(start 433.83962 -175.597058)
		(end 432.822858 -176.61382)
		(width 0.254)
		(layer "F.Cu")
		(net "GND")
	)
	(segment
		(start 276.373082 -289.966654)
		(end 275.268182 -289.966654)
		(width 0.381)
		(layer "F.Cu")
		(net "GND")
	)
	(segment
		(start 421.840914 -311.216802)
		(end 420.736014 -311.216802)
		(width 0.381)
		(layer "F.Cu")
		(net "GND")
	)
	(segment
		(start 196.329554 -78.40218)
		(end 196.307964 -78.42377)
		(width 0.3556)
		(layer "F.Cu")
		(net "GND")
	)
	(segment
		(start 48.854614 -308.666642)
		(end 49.959514 -308.666642)
		(width 0.381)
		(layer "F.Cu")
		(net "GND")
	)
	(segment
		(start 170.457114 -239.81664)
		(end 171.562014 -239.81664)
		(width 0.381)
		(layer "F.Cu")
		(net "GND")
	)
	(segment
		(start 100.362512 -233.064304)
		(end 100.362512 -232.528618)
		(width 0.254)
		(layer "F.Cu")
		(net "GND")
	)
	(segment
		(start 26.02992 -428.081948)
		(end 25.39492 -428.081948)
		(width 0.3556)
		(layer "F.Cu")
		(net "GND")
	)
	(segment
		(start 378.84608 -240.388902)
		(end 378.84608 -239.853216)
		(width 0.2032)
		(layer "F.Cu")
		(net "GND")
	)
	(segment
		(start 117.89664 -403.128988)
		(end 117.89664 -403.245828)
		(width 0.3556)
		(layer "F.Cu")
		(net "GND")
	)
	(segment
		(start 266.619482 -250.866656)
		(end 267.724382 -250.866656)
		(width 0.381)
		(layer "F.Cu")
		(net "GND")
	)
	(segment
		(start 33.767014 -205.816708)
		(end 34.871914 -205.816708)
		(width 0.381)
		(layer "F.Cu")
		(net "GND")
	)
	(segment
		(start 91.074494 -271.289272)
		(end 91.074494 -271.825212)
		(width 0.2032)
		(layer "F.Cu")
		(net "GND")
	)
	(segment
		(start 21.456396 -385.526026)
		(end 21.456396 -386.084826)
		(width 0.3556)
		(layer "F.Cu")
		(net "GND")
	)
	(segment
		(start 96.133412 -246.900192)
		(end 96.133412 -246.364506)
		(width 0.2032)
		(layer "F.Cu")
		(net "GND")
	)
	(segment
		(start 370.498116 -281.869896)
		(end 370.497862 -282.405836)
		(width 0.254)
		(layer "F.Cu")
		(net "GND")
	)
	(segment
		(start 448.572382 -294.216582)
		(end 447.467482 -294.216582)
		(width 0.381)
		(layer "F.Cu")
		(net "GND")
	)
	(segment
		(start 385.424934 -238.761524)
		(end 384.485134 -238.225584)
		(width 0.254)
		(layer "F.Cu")
		(net "GND")
	)
	(segment
		(start 33.034478 -161.570162)
		(end 32.350202 -161.570162)
		(width 0.254)
		(layer "F.Cu")
		(net "GND")
	)
	(segment
		(start 339.374734 -248.528078)
		(end 339.374734 -247.992138)
		(width 0.2032)
		(layer "F.Cu")
		(net "GND")
	)
	(segment
		(start 85.177376 -278.711406)
		(end 85.274404 -278.614378)
		(width 0.2032)
		(layer "F.Cu")
		(net "GND")
	)
	(segment
		(start 298.233338 -367.755932)
		(end 298.070524 -367.755932)
		(width 0.381)
		(layer "F.Cu")
		(net "GND")
	)
	(segment
		(start 125.377448 -279.150064)
		(end 125.377194 -279.150318)
		(width 0.254)
		(layer "F.Cu")
		(net "GND")
	)
	(segment
		(start 453.121014 -276.366732)
		(end 452.016114 -276.366732)
		(width 0.381)
		(layer "F.Cu")
		(net "GND")
	)
	(segment
		(start 335.14538 -223.297496)
		(end 335.14538 -222.76181)
		(width 0.2032)
		(layer "F.Cu")
		(net "GND")
	)
	(segment
		(start 25.992836 -127.159512)
		(end 26.18232 -127.348996)
		(width 0.381)
		(layer "F.Cu")
		(net "GND")
	)
	(segment
		(start 38.315646 -244.916706)
		(end 37.210746 -244.916706)
		(width 0.381)
		(layer "F.Cu")
		(net "GND")
	)
	(segment
		(start 375.55678 -242.295172)
		(end 375.557034 -242.294918)
		(width 0.2032)
		(layer "F.Cu")
		(net "GND")
	)
	(segment
		(start 116.783866 -408.11069)
		(end 116.783866 -408.74569)
		(width 0.3556)
		(layer "F.Cu")
		(net "GND")
	)
	(segment
		(start 462.555082 -200.716642)
		(end 463.659982 -200.716642)
		(width 0.381)
		(layer "F.Cu")
		(net "GND")
	)
	(segment
		(start 348.30258 -220.041978)
		(end 348.302834 -220.041724)
		(width 0.254)
		(layer "F.Cu")
		(net "GND")
	)
	(segment
		(start 376.49658 -226.553268)
		(end 376.49658 -226.017582)
		(width 0.254)
		(layer "F.Cu")
		(net "GND")
	)
	(segment
		(start 195.25615 -42.549572)
		(end 196.030596 -42.549572)
		(width 0.3556)
		(layer "F.Cu")
		(net "GND")
	)
	(segment
		(start 162.913314 -269.566644)
		(end 161.808414 -269.566644)
		(width 0.381)
		(layer "F.Cu")
		(net "GND")
	)
	(segment
		(start 202.971146 -273.816572)
		(end 204.076046 -273.816572)
		(width 0.381)
		(layer "F.Cu")
		(net "GND")
	)
	(segment
		(start 433.484782 -258.516628)
		(end 434.589682 -258.516628)
		(width 0.381)
		(layer "F.Cu")
		(net "GND")
	)
	(segment
		(start 189.26302 -17.655032)
		(end 189.26302 -16.551148)
		(width 0.3556)
		(layer "F.Cu")
		(net "GND")
	)
	(segment
		(start 60.947046 -201.56678)
		(end 62.051946 -201.56678)
		(width 0.381)
		(layer "F.Cu")
		(net "GND")
	)
	(segment
		(start 285.211266 -362.184696)
		(end 285.458916 -362.184696)
		(width 0.2032)
		(layer "F.Cu")
		(net "GND")
	)
	(segment
		(start 87.785194 -273.730974)
		(end 87.785194 -274.266914)
		(width 0.2032)
		(layer "F.Cu")
		(net "GND")
	)
	(segment
		(start 199.527414 -224.516696)
		(end 200.632314 -224.516696)
		(width 0.381)
		(layer "F.Cu")
		(net "GND")
	)
	(segment
		(start 383.655062 -269.38351)
		(end 383.655062 -268.84757)
		(width 0.254)
		(layer "F.Cu")
		(net "GND")
	)
	(segment
		(start 42.415714 -202.416664)
		(end 41.310814 -202.416664)
		(width 0.381)
		(layer "F.Cu")
		(net "GND")
	)
	(segment
		(start 14.426946 -394.231876)
		(end 15.036546 -394.231876)
		(width 0.3556)
		(layer "F.Cu")
		(net "GND")
	)
	(segment
		(start 60.947046 -212.616796)
		(end 62.051946 -212.616796)
		(width 0.381)
		(layer "F.Cu")
		(net "GND")
	)
	(segment
		(start 134.195566 -242.830858)
		(end 134.195566 -242.294918)
		(width 0.2032)
		(layer "F.Cu")
		(net "GND")
	)
	(segment
		(start 345.123516 -284.033468)
		(end 345.123262 -284.033722)
		(width 0.254)
		(layer "F.Cu")
		(net "GND")
	)
	(segment
		(start 421.840914 -298.466764)
		(end 420.736014 -298.466764)
		(width 0.381)
		(layer "F.Cu")
		(net "GND")
	)
	(segment
		(start 330.896976 -57.605168)
		(end 331.897482 -57.605168)
		(width 0.2032)
		(layer "F.Cu")
		(net "GND")
	)
	(segment
		(start 432.379882 -286.56661)
		(end 433.484782 -286.56661)
		(width 0.381)
		(layer "F.Cu")
		(net "GND")
	)
	(segment
		(start 131.547108 -12.495276)
		(end 131.547108 -13.600176)
		(width 0.3556)
		(layer "F.Cu")
		(net "GND")
	)
	(segment
		(start 22.123146 -295.06672)
		(end 23.228046 -295.06672)
		(width 0.381)
		(layer "F.Cu")
		(net "GND")
	)
	(segment
		(start 286.255714 -285.716726)
		(end 287.360614 -285.716726)
		(width 0.381)
		(layer "F.Cu")
		(net "GND")
	)
	(segment
		(start 181.444646 -263.616694)
		(end 182.549546 -263.616694)
		(width 0.381)
		(layer "F.Cu")
		(net "GND")
	)
	(segment
		(start 54.42458 -154.077924)
		(end 54.42458 -153.739088)
		(width 0.2032)
		(layer "F.Cu")
		(net "GND")
	)
	(segment
		(start 59.842146 -265.316716)
		(end 60.947046 -265.316716)
		(width 0.381)
		(layer "F.Cu")
		(net "GND")
	)
	(segment
		(start 337.604862 -273.730974)
		(end 337.604862 -274.266914)
		(width 0.2032)
		(layer "F.Cu")
		(net "GND")
	)
	(segment
		(start 162.913314 -245.76659)
		(end 161.808414 -245.76659)
		(width 0.381)
		(layer "F.Cu")
		(net "GND")
	)
	(segment
		(start 85.39607 -342.51773)
		(end 85.39607 -343.096088)
		(width 0.3556)
		(layer "F.Cu")
		(net "GND")
	)
	(segment
		(start 149.03704 -131.932934)
		(end 149.67204 -131.932934)
		(width 0.3556)
		(layer "F.Cu")
		(net "GND")
	)
	(segment
		(start 23.228046 -265.316716)
		(end 24.332946 -265.316716)
		(width 0.381)
		(layer "F.Cu")
		(net "GND")
	)
	(segment
		(start 65.047114 -228.766624)
		(end 66.152014 -228.766624)
		(width 0.381)
		(layer "F.Cu")
		(net "GND")
	)
	(segment
		(start 372.267734 -248.528078)
		(end 372.26748 -248.527824)
		(width 0.2032)
		(layer "F.Cu")
		(net "GND")
	)
	(segment
		(start 56.398414 -269.566644)
		(end 57.503314 -269.566644)
		(width 0.381)
		(layer "F.Cu")
		(net "GND")
	)
	(segment
		(start 129.496566 -236.319568)
		(end 129.496566 -235.783882)
		(width 0.2032)
		(layer "F.Cu")
		(net "GND")
	)
	(segment
		(start 307.782214 -315.46673)
		(end 308.887114 -315.46673)
		(width 0.381)
		(layer "F.Cu")
		(net "GND")
	)
	(segment
		(start 53.403246 -265.316716)
		(end 54.508146 -265.316716)
		(width 0.381)
		(layer "F.Cu")
		(net "GND")
	)
	(segment
		(start 405.648414 -260.21665)
		(end 406.753314 -260.21665)
		(width 0.381)
		(layer "F.Cu")
		(net "GND")
	)
	(segment
		(start 343.243916 -272.639028)
		(end 343.243662 -272.639282)
		(width 0.2032)
		(layer "F.Cu")
		(net "GND")
	)
	(segment
		(start 29.869638 -124.062236)
		(end 29.869638 -124.794264)
		(width 0.381)
		(layer "F.Cu")
		(net "GND")
	)
	(segment
		(start 374.617234 -228.180646)
		(end 374.617234 -227.64496)
		(width 0.2032)
		(layer "F.Cu")
		(net "GND")
	)
	(segment
		(start 352.172016 -271.289526)
		(end 352.172016 -271.825212)
		(width 0.2032)
		(layer "F.Cu")
		(net "GND")
	)
	(segment
		(start 289.250882 -239.81664)
		(end 290.355782 -239.81664)
		(width 0.381)
		(layer "F.Cu")
		(net "GND")
	)
	(segment
		(start 346.532962 -282.683966)
		(end 346.532962 -283.219906)
		(width 0.2032)
		(layer "F.Cu")
		(net "GND")
	)
	(segment
		(start 346.063316 -275.35886)
		(end 346.063316 -275.894546)
		(width 0.2032)
		(layer "F.Cu")
		(net "GND")
	)
	(segment
		(start 301.343314 -220.266768)
		(end 302.664114 -220.266768)
		(width 0.381)
		(layer "F.Cu")
		(net "GND")
	)
	(segment
		(start 100.002848 -257.988816)
		(end 100.002594 -257.98907)
		(width 0.2032)
		(layer "F.Cu")
		(net "GND")
	)
	(segment
		(start 26.223214 -312.91657)
		(end 27.328114 -312.91657)
		(width 0.381)
		(layer "F.Cu")
		(net "GND")
	)
	(segment
		(start 289.250882 -289.966654)
		(end 290.355782 -289.966654)
		(width 0.381)
		(layer "F.Cu")
		(net "GND")
	)
	(segment
		(start 191.89827 -425.405042)
		(end 192.74282 -425.405042)
		(width 0.3556)
		(layer "F.Cu")
		(net "GND")
	)
	(segment
		(start 311.882282 -286.56661)
		(end 312.987182 -286.56661)
		(width 0.381)
		(layer "F.Cu")
		(net "GND")
	)
	(segment
		(start 267.724382 -238.116618)
		(end 268.829282 -238.116618)
		(width 0.381)
		(layer "F.Cu")
		(net "GND")
	)
	(segment
		(start 337.495134 -245.27256)
		(end 337.49488 -245.272306)
		(width 0.2032)
		(layer "F.Cu")
		(net "GND")
	)
	(segment
		(start 343.819734 -49.859692)
		(end 343.81948 -49.859946)
		(width 0.254)
		(layer "F.Cu")
		(net "GND")
	)
	(segment
		(start 337.495134 -217.600276)
		(end 337.495134 -217.064336)
		(width 0.2032)
		(layer "F.Cu")
		(net "GND")
	)
	(segment
		(start 429.384714 -273.816572)
		(end 430.489614 -273.816572)
		(width 0.381)
		(layer "F.Cu")
		(net "GND")
	)
	(segment
		(start 457.221082 -291.666676)
		(end 456.116182 -291.666676)
		(width 0.381)
		(layer "F.Cu")
		(net "GND")
	)
	(segment
		(start 92.844112 -236.319822)
		(end 92.844366 -236.319568)
		(width 0.2032)
		(layer "F.Cu")
		(net "GND")
	)
	(segment
		(start 161.808414 -198.166736)
		(end 162.913314 -198.166736)
		(width 0.381)
		(layer "F.Cu")
		(net "GND")
	)
	(segment
		(start 45.859446 -292.516814)
		(end 46.964346 -292.516814)
		(width 0.381)
		(layer "F.Cu")
		(net "GND")
	)
	(segment
		(start 167.715946 -220.266768)
		(end 166.357046 -220.266768)
		(width 0.381)
		(layer "F.Cu")
		(net "GND")
	)
	(segment
		(start 300.238414 -201.56678)
		(end 301.343314 -201.56678)
		(width 0.381)
		(layer "F.Cu")
		(net "GND")
	)
	(segment
		(start 125.847094 -263.68629)
		(end 125.847348 -263.686544)
		(width 0.2032)
		(layer "F.Cu")
		(net "GND")
	)
	(segment
		(start 18.679414 -289.966654)
		(end 19.784314 -289.966654)
		(width 0.381)
		(layer "F.Cu")
		(net "GND")
	)
	(segment
		(start 415.101786 -344.010996)
		(end 416.042094 -344.010996)
		(width 0.508)
		(layer "F.Cu")
		(net "GND")
	)
	(segment
		(start 349.352362 -276.708362)
		(end 349.352616 -276.708616)
		(width 0.254)
		(layer "F.Cu")
		(net "GND")
	)
	(segment
		(start 286.255714 -258.516628)
		(end 287.360614 -258.516628)
		(width 0.381)
		(layer "F.Cu")
		(net "GND")
	)
	(segment
		(start 386.83438 -236.319822)
		(end 387.30428 -236.597952)
		(width 0.254)
		(layer "F.Cu")
		(net "GND")
	)
	(segment
		(start 96.133412 -250.15571)
		(end 96.133412 -249.620024)
		(width 0.2032)
		(layer "F.Cu")
		(net "GND")
	)
	(segment
		(start 48.854614 -196.466714)
		(end 49.959514 -196.466714)
		(width 0.381)
		(layer "F.Cu")
		(net "GND")
	)
	(segment
		(start 180.64988 -130.666998)
		(end 180.64988 -131.280408)
		(width 0.3556)
		(layer "F.Cu")
		(net "GND")
	)
	(segment
		(start 7.035546 -225.36658)
		(end 8.140446 -225.36658)
		(width 0.381)
		(layer "F.Cu")
		(net "GND")
	)
	(segment
		(start 293.799514 -223.666558)
		(end 292.694614 -223.666558)
		(width 0.381)
		(layer "F.Cu")
		(net "GND")
	)
	(segment
		(start 463.659982 -204.116686)
		(end 464.764882 -204.116686)
		(width 0.381)
		(layer "F.Cu")
		(net "GND")
	)
	(segment
		(start 340.894162 -255.011682)
		(end 340.894162 -255.547368)
		(width 0.2032)
		(layer "F.Cu")
		(net "GND")
	)
	(segment
		(start 200.632314 -316.316614)
		(end 201.737214 -316.316614)
		(width 0.381)
		(layer "F.Cu")
		(net "GND")
	)
	(segment
		(start 428.283116 -109.66704)
		(end 428.283116 -110.27664)
		(width 0.4572)
		(layer "F.Cu")
		(net "GND")
	)
	(segment
		(start 52.082446 -234.716574)
		(end 53.403246 -234.716574)
		(width 0.381)
		(layer "F.Cu")
		(net "GND")
	)
	(segment
		(start 89.555066 -227.367084)
		(end 89.554812 -227.36683)
		(width 0.2032)
		(layer "F.Cu")
		(net "GND")
	)
	(segment
		(start 456.116182 -233.86669)
		(end 455.011282 -233.86669)
		(width 0.381)
		(layer "F.Cu")
		(net "GND")
	)
	(segment
		(start 59.842146 -251.716794)
		(end 60.947046 -251.716794)
		(width 0.381)
		(layer "F.Cu")
		(net "GND")
	)
	(segment
		(start 172.8724 -94.738698)
		(end 172.8724 -95.367348)
		(width 0.3556)
		(layer "F.Cu")
		(net "GND")
	)
	(segment
		(start 247.596914 -86.35746)
		(end 249.46483 -86.35746)
		(width 0.3556)
		(layer "F.Cu")
		(net "GND")
	)
	(segment
		(start 405.648414 -300.166786)
		(end 406.753314 -300.166786)
		(width 0.381)
		(layer "F.Cu")
		(net "GND")
	)
	(segment
		(start 460.664814 -234.716574)
		(end 459.559914 -234.716574)
		(width 0.381)
		(layer "F.Cu")
		(net "GND")
	)
	(segment
		(start 457.221082 -221.116652)
		(end 456.116182 -221.116652)
		(width 0.381)
		(layer "F.Cu")
		(net "GND")
	)
	(segment
		(start 129.496312 -220.041978)
		(end 129.496566 -219.506038)
		(width 0.254)
		(layer "F.Cu")
		(net "GND")
	)
	(segment
		(start 176.896014 -282.316682)
		(end 178.000914 -282.316682)
		(width 0.381)
		(layer "F.Cu")
		(net "GND")
	)
	(segment
		(start 86.265766 -224.925382)
		(end 86.265766 -224.389442)
		(width 0.254)
		(layer "F.Cu")
		(net "GND")
	)
	(segment
		(start 311.882282 -266.1666)
		(end 312.987182 -266.1666)
		(width 0.381)
		(layer "F.Cu")
		(net "GND")
	)
	(segment
		(start 383.07518 -216.78646)
		(end 383.07518 -216.250774)
		(width 0.254)
		(layer "F.Cu")
		(net "GND")
	)
	(segment
		(start 211.619846 -227.066602)
		(end 212.724746 -227.066602)
		(width 0.381)
		(layer "F.Cu")
		(net "GND")
	)
	(segment
		(start 129.496312 -241.203226)
		(end 129.496566 -241.202972)
		(width 0.2032)
		(layer "F.Cu")
		(net "GND")
	)
	(segment
		(start 415.198814 -287.416748)
		(end 414.297114 -287.416748)
		(width 0.381)
		(layer "F.Cu")
		(net "GND")
	)
	(segment
		(start 97.183448 -267.219938)
		(end 97.183448 -267.755878)
		(width 0.2032)
		(layer "F.Cu")
		(net "GND")
	)
	(segment
		(start 111.25708 -398.424908)
		(end 111.690912 -398.85874)
		(width 0.3556)
		(layer "F.Cu")
		(net "GND")
	)
	(segment
		(start 263.624314 -195.616576)
		(end 264.729214 -195.616576)
		(width 0.381)
		(layer "F.Cu")
		(net "GND")
	)
	(segment
		(start 124.437648 -261.244588)
		(end 124.437394 -261.244842)
		(width 0.2032)
		(layer "F.Cu")
		(net "GND")
	)
	(segment
		(start 127.616712 -242.295172)
		(end 127.616966 -242.294918)
		(width 0.2032)
		(layer "F.Cu")
		(net "GND")
	)
	(segment
		(start 320.8401 -76.985114)
		(end 321.8561 -76.985114)
		(width 0.3556)
		(layer "F.Cu")
		(net "GND")
	)
	(segment
		(start 27.547062 -7.215124)
		(end 27.547062 -8.320024)
		(width 0.3556)
		(layer "F.Cu")
		(net "GND")
	)
	(segment
		(start 432.379882 -280.61666)
		(end 433.484782 -280.61666)
		(width 0.381)
		(layer "F.Cu")
		(net "GND")
	)
	(segment
		(start 211.619846 -285.716726)
		(end 210.514946 -285.716726)
		(width 0.381)
		(layer "F.Cu")
		(net "GND")
	)
	(segment
		(start 181.444646 -317.166752)
		(end 180.339746 -317.166752)
		(width 0.381)
		(layer "F.Cu")
		(net "GND")
	)
	(segment
		(start 422.945814 -313.766708)
		(end 421.840914 -313.766708)
		(width 0.381)
		(layer "F.Cu")
		(net "GND")
	)
	(segment
		(start 208.176114 -244.066568)
		(end 209.281014 -244.066568)
		(width 0.381)
		(layer "F.Cu")
		(net "GND")
	)
	(segment
		(start 98.482912 -216.250774)
		(end 98.483166 -216.25052)
		(width 0.254)
		(layer "F.Cu")
		(net "GND")
	)
	(segment
		(start 386.004562 -269.66164)
		(end 386.785866 -269.66164)
		(width 0.254)
		(layer "F.Cu")
		(net "GND")
	)
	(segment
		(start 138.534648 -284.033468)
		(end 138.534394 -284.033722)
		(width 0.2032)
		(layer "F.Cu")
		(net "GND")
	)
	(segment
		(start 179.31257 -354.02901)
		(end 178.985164 -354.02901)
		(width 0.2032)
		(layer "F.Cu")
		(net "GND")
	)
	(segment
		(start 198.77913 -111.978948)
		(end 198.77913 -113.824258)
		(width 0.3556)
		(layer "F.Cu")
		(net "GND")
	)
	(segment
		(start 307.782214 -309.51678)
		(end 308.887114 -309.51678)
		(width 0.381)
		(layer "F.Cu")
		(net "GND")
	)
	(segment
		(start 370.498116 -265.592306)
		(end 370.498116 -266.127992)
		(width 0.254)
		(layer "F.Cu")
		(net "GND")
	)
	(segment
		(start 110.340648 -281.869896)
		(end 110.340648 -282.405582)
		(width 0.254)
		(layer "F.Cu")
		(net "GND")
	)
	(segment
		(start 339.484462 -265.592306)
		(end 339.484462 -266.128246)
		(width 0.254)
		(layer "F.Cu")
		(net "GND")
	)
	(segment
		(start 460.664814 -261.916672)
		(end 459.559914 -261.916672)
		(width 0.381)
		(layer "F.Cu")
		(net "GND")
	)
	(segment
		(start 87.205312 -216.250774)
		(end 87.205058 -216.25052)
		(width 0.2032)
		(layer "F.Cu")
		(net "GND")
	)
	(segment
		(start 53.403246 -287.416748)
		(end 54.508146 -287.416748)
		(width 0.381)
		(layer "F.Cu")
		(net "GND")
	)
	(segment
		(start 420.736014 -227.066602)
		(end 421.840914 -227.066602)
		(width 0.381)
		(layer "F.Cu")
		(net "GND")
	)
	(segment
		(start 166.357046 -283.166566)
		(end 167.461946 -283.166566)
		(width 0.381)
		(layer "F.Cu")
		(net "GND")
	)
	(segment
		(start 271.168114 -206.666592)
		(end 270.063214 -206.666592)
		(width 0.381)
		(layer "F.Cu")
		(net "GND")
	)
	(segment
		(start 387.883908 -262.058404)
		(end 387.884162 -262.058404)
		(width 0.254)
		(layer "F.Cu")
		(net "GND")
	)
	(segment
		(start 137.129774 -258.80314)
		(end 137.124694 -258.80314)
		(width 0.254)
		(layer "F.Cu")
		(net "GND")
	)
	(segment
		(start 256.080514 -197.316598)
		(end 257.185414 -197.316598)
		(width 0.381)
		(layer "F.Cu")
		(net "GND")
	)
	(segment
		(start 335.784444 -60.128404)
		(end 335.784444 -59.75096)
		(width 0.2032)
		(layer "F.Cu")
		(net "GND")
	)
	(segment
		(start 463.659982 -245.76659)
		(end 464.764882 -245.76659)
		(width 0.381)
		(layer "F.Cu")
		(net "GND")
	)
	(segment
		(start 382.245362 -286.47517)
		(end 382.245616 -286.475424)
		(width 0.2032)
		(layer "F.Cu")
		(net "GND")
	)
	(segment
		(start 368.97818 -223.297496)
		(end 368.97818 -222.76181)
		(width 0.254)
		(layer "F.Cu")
		(net "GND")
	)
	(segment
		(start 414.297114 -206.666592)
		(end 415.689796 -206.666592)
		(width 0.381)
		(layer "F.Cu")
		(net "GND")
	)
	(segment
		(start 182.549546 -281.466798)
		(end 181.444646 -281.466798)
		(width 0.381)
		(layer "F.Cu")
		(net "GND")
	)
	(segment
		(start 215.719914 -278.916638)
		(end 216.824814 -278.916638)
		(width 0.381)
		(layer "F.Cu")
		(net "GND")
	)
	(segment
		(start 12.240514 -196.466714)
		(end 13.345414 -196.466714)
		(width 0.381)
		(layer "F.Cu")
		(net "GND")
	)
	(segment
		(start 98.592894 -255.011682)
		(end 98.592894 -255.547622)
		(width 0.2032)
		(layer "F.Cu")
		(net "GND")
	)
	(segment
		(start 332.7527 -269.938246)
		(end 333.274162 -269.66164)
		(width 0.2032)
		(layer "F.Cu")
		(net "GND")
	)
	(segment
		(start 297.899582 -269.566644)
		(end 299.004482 -269.566644)
		(width 0.381)
		(layer "F.Cu")
		(net "GND")
	)
	(segment
		(start 452.016114 -285.716726)
		(end 450.911214 -285.716726)
		(width 0.381)
		(layer "F.Cu")
		(net "GND")
	)
	(segment
		(start 428.279814 -208.366614)
		(end 429.384714 -208.366614)
		(width 0.381)
		(layer "F.Cu")
		(net "GND")
	)
	(segment
		(start 386.004562 -282.683966)
		(end 386.02412 -282.703524)
		(width 0.254)
		(layer "F.Cu")
		(net "GND")
	)
	(segment
		(start 108.461048 -278.614378)
		(end 108.461048 -279.150064)
		(width 0.254)
		(layer "F.Cu")
		(net "GND")
	)
	(segment
		(start 347.472762 -260.430518)
		(end 347.473016 -260.430772)
		(width 0.2032)
		(layer "F.Cu")
		(net "GND")
	)
	(segment
		(start 185.544714 -286.56661)
		(end 184.439814 -286.56661)
		(width 0.381)
		(layer "F.Cu")
		(net "GND")
	)
	(segment
		(start 120.568466 -230.622602)
		(end 120.568212 -230.622348)
		(width 0.254)
		(layer "F.Cu")
		(net "GND")
	)
	(segment
		(start 249.28703 -45.379132)
		(end 249.28703 -45.988732)
		(width 0.4572)
		(layer "F.Cu")
		(net "GND")
	)
	(segment
		(start 91.904312 -242.830858)
		(end 91.904312 -242.295172)
		(width 0.2032)
		(layer "F.Cu")
		(net "GND")
	)
	(segment
		(start 182.549546 -272.116804)
		(end 181.444646 -272.116804)
		(width 0.381)
		(layer "F.Cu")
		(net "GND")
	)
	(segment
		(start 437.2356 -95.113348)
		(end 437.515 -94.833948)
		(width 0.3556)
		(layer "F.Cu")
		(net "GND")
	)
	(segment
		(start 49.959514 -215.166702)
		(end 48.854614 -215.166702)
		(width 0.381)
		(layer "F.Cu")
		(net "GND")
	)
	(segment
		(start 374.61698 -242.295172)
		(end 374.617234 -242.294918)
		(width 0.2032)
		(layer "F.Cu")
		(net "GND")
	)
	(segment
		(start 119.738648 -278.614378)
		(end 119.738394 -279.150318)
		(width 0.254)
		(layer "F.Cu")
		(net "GND")
	)
	(segment
		(start 127.616712 -234.69219)
		(end 127.616966 -234.691936)
		(width 0.2032)
		(layer "F.Cu")
		(net "GND")
	)
	(segment
		(start 195.427346 -217.716608)
		(end 196.532246 -217.716608)
		(width 0.381)
		(layer "F.Cu")
		(net "GND")
	)
	(segment
		(start 18.230088 -107.123484)
		(end 17.445482 -107.123484)
		(width 0.3556)
		(layer "F.Cu")
		(net "GND")
	)
	(segment
		(start 289.250882 -250.866656)
		(end 290.355782 -250.866656)
		(width 0.381)
		(layer "F.Cu")
		(net "GND")
	)
	(segment
		(start 212.724746 -289.11677)
		(end 211.619846 -289.11677)
		(width 0.381)
		(layer "F.Cu")
		(net "GND")
	)
	(segment
		(start 267.724382 -294.216582)
		(end 268.829282 -294.216582)
		(width 0.381)
		(layer "F.Cu")
		(net "GND")
	)
	(segment
		(start 8.140446 -263.616694)
		(end 9.245346 -263.616694)
		(width 0.381)
		(layer "F.Cu")
		(net "GND")
	)
	(segment
		(start 261.285482 -288.266632)
		(end 260.180582 -288.266632)
		(width 0.381)
		(layer "F.Cu")
		(net "GND")
	)
	(segment
		(start 428.279814 -268.71676)
		(end 429.384714 -268.71676)
		(width 0.381)
		(layer "F.Cu")
		(net "GND")
	)
	(segment
		(start 184.439814 -249.166634)
		(end 185.544714 -249.166634)
		(width 0.381)
		(layer "F.Cu")
		(net "GND")
	)
	(segment
		(start 294.904414 -304.416714)
		(end 293.799514 -304.416714)
		(width 0.381)
		(layer "F.Cu")
		(net "GND")
	)
	(segment
		(start 254.975614 -289.11677)
		(end 256.080514 -289.11677)
		(width 0.381)
		(layer "F.Cu")
		(net "GND")
	)
	(segment
		(start 352.171762 -277.800562)
		(end 352.171762 -278.336248)
		(width 0.2032)
		(layer "F.Cu")
		(net "GND")
	)
	(segment
		(start 186.649614 -207.51673)
		(end 185.544714 -207.51673)
		(width 0.381)
		(layer "F.Cu")
		(net "GND")
	)
	(segment
		(start 49.959514 -235.566712)
		(end 51.064414 -235.566712)
		(width 0.381)
		(layer "F.Cu")
		(net "GND")
	)
	(segment
		(start 199.527414 -280.61666)
		(end 200.632314 -280.61666)
		(width 0.381)
		(layer "F.Cu")
		(net "GND")
	)
	(segment
		(start 453.121014 -258.516628)
		(end 452.016114 -258.516628)
		(width 0.381)
		(layer "F.Cu")
		(net "GND")
	)
	(segment
		(start 26.223214 -264.466578)
		(end 27.328114 -264.466578)
		(width 0.381)
		(layer "F.Cu")
		(net "GND")
	)
	(segment
		(start 365.96955 -405.9936)
		(end 365.3282 -405.9936)
		(width 0.3556)
		(layer "F.Cu")
		(net "GND")
	)
	(segment
		(start 138.534648 -281.869896)
		(end 138.534394 -282.405836)
		(width 0.254)
		(layer "F.Cu")
		(net "GND")
	)
	(segment
		(start 348.08287 -47.482252)
		(end 348.029022 -47.5361)
		(width 0.1524)
		(layer "F.Cu")
		(net "GND")
	)
	(segment
		(start 427.045882 -275.516594)
		(end 425.940982 -275.516594)
		(width 0.381)
		(layer "F.Cu")
		(net "GND")
	)
	(segment
		(start 211.619846 -250.016772)
		(end 212.724746 -250.016772)
		(width 0.381)
		(layer "F.Cu")
		(net "GND")
	)
	(segment
		(start 123.497848 -281.869896)
		(end 123.497848 -282.405582)
		(width 0.254)
		(layer "F.Cu")
		(net "GND")
	)
	(segment
		(start 381.305562 -259.894832)
		(end 381.305562 -260.430772)
		(width 0.2032)
		(layer "F.Cu")
		(net "GND")
	)
	(segment
		(start 266.619482 -247.466612)
		(end 267.724382 -247.466612)
		(width 0.381)
		(layer "F.Cu")
		(net "GND")
	)
	(segment
		(start 111.640112 -216.78646)
		(end 111.640112 -216.250774)
		(width 0.254)
		(layer "F.Cu")
		(net "GND")
	)
	(segment
		(start 27.328114 -238.116618)
		(end 28.433014 -238.116618)
		(width 0.381)
		(layer "F.Cu")
		(net "GND")
	)
	(segment
		(start 374.726962 -281.05608)
		(end 374.726962 -281.59202)
		(width 0.2032)
		(layer "F.Cu")
		(net "GND")
	)
	(segment
		(start 167.461946 -317.166752)
		(end 166.357046 -317.166752)
		(width 0.381)
		(layer "F.Cu")
		(net "GND")
	)
	(segment
		(start 459.559914 -290.816792)
		(end 460.664814 -290.816792)
		(width 0.381)
		(layer "F.Cu")
		(net "GND")
	)
	(segment
		(start 45.859446 -214.316564)
		(end 46.964346 -214.316564)
		(width 0.381)
		(layer "F.Cu")
		(net "GND")
	)
	(segment
		(start 53.403246 -283.166566)
		(end 54.508146 -283.166566)
		(width 0.381)
		(layer "F.Cu")
		(net "GND")
	)
	(segment
		(start 162.913314 -306.96662)
		(end 164.018214 -306.96662)
		(width 0.381)
		(layer "F.Cu")
		(net "GND")
	)
	(segment
		(start 372.377716 -274.26666)
		(end 372.377462 -274.266914)
		(width 0.254)
		(layer "F.Cu")
		(net "GND")
	)
	(segment
		(start 301.343314 -242.3668)
		(end 302.448214 -242.3668)
		(width 0.381)
		(layer "F.Cu")
		(net "GND")
	)
	(segment
		(start 26.223214 -284.866588)
		(end 27.328114 -284.866588)
		(width 0.381)
		(layer "F.Cu")
		(net "GND")
	)
	(segment
		(start 443.367414 -311.216802)
		(end 444.472314 -311.216802)
		(width 0.381)
		(layer "F.Cu")
		(net "GND")
	)
	(segment
		(start 290.355782 -200.716642)
		(end 291.460682 -200.716642)
		(width 0.381)
		(layer "F.Cu")
		(net "GND")
	)
	(segment
		(start 305.443382 -210.066636)
		(end 306.764182 -210.066636)
		(width 0.381)
		(layer "F.Cu")
		(net "GND")
	)
	(segment
		(start 210.514946 -208.366614)
		(end 211.619846 -208.366614)
		(width 0.381)
		(layer "F.Cu")
		(net "GND")
	)
	(segment
		(start 33.767014 -202.416664)
		(end 34.871914 -202.416664)
		(width 0.381)
		(layer "F.Cu")
		(net "GND")
	)
	(segment
		(start 65.047114 -278.916638)
		(end 66.152014 -278.916638)
		(width 0.381)
		(layer "F.Cu")
		(net "GND")
	)
	(segment
		(start 308.35092 -425.186602)
		(end 308.35092 -425.831)
		(width 0.3556)
		(layer "F.Cu")
		(net "GND")
	)
	(segment
		(start 215.719914 -207.51673)
		(end 216.824814 -207.51673)
		(width 0.381)
		(layer "F.Cu")
		(net "GND")
	)
	(segment
		(start 445.577214 -210.916774)
		(end 444.472314 -210.916774)
		(width 0.381)
		(layer "F.Cu")
		(net "GND")
	)
	(segment
		(start 118.798848 -270.475456)
		(end 118.798594 -271.011396)
		(width 0.254)
		(layer "F.Cu")
		(net "GND")
	)
	(segment
		(start 128.03505 -58.003948)
		(end 128.03505 -58.740548)
		(width 0.3556)
		(layer "F.Cu")
		(net "GND")
	)
	(segment
		(start 272.273014 -260.21665)
		(end 271.168114 -260.21665)
		(width 0.381)
		(layer "F.Cu")
		(net "GND")
	)
	(segment
		(start 121.148094 -281.05608)
		(end 121.148094 -281.591512)
		(width 0.254)
		(layer "F.Cu")
		(net "GND")
	)
	(segment
		(start 281.707082 -241.516662)
		(end 282.811982 -241.516662)
		(width 0.381)
		(layer "F.Cu")
		(net "GND")
	)
	(segment
		(start 386.004562 -271.289272)
		(end 386.474462 -271.011396)
		(width 0.254)
		(layer "F.Cu")
		(net "GND")
	)
	(segment
		(start 167.461946 -298.466764)
		(end 166.357046 -298.466764)
		(width 0.381)
		(layer "F.Cu")
		(net "GND")
	)
	(segment
		(start 345.554554 -39.946072)
		(end 345.15171 -40.348916)
		(width 0.2032)
		(layer "F.Cu")
		(net "GND")
	)
	(segment
		(start 91.544648 -271.011142)
		(end 91.544394 -271.011396)
		(width 0.2032)
		(layer "F.Cu")
		(net "GND")
	)
	(segment
		(start 457.221082 -207.51673)
		(end 456.116182 -207.51673)
		(width 0.381)
		(layer "F.Cu")
		(net "GND")
	)
	(segment
		(start 409.748482 -280.61666)
		(end 410.853382 -280.61666)
		(width 0.381)
		(layer "F.Cu")
		(net "GND")
	)
	(segment
		(start 281.707082 -261.066788)
		(end 282.811982 -261.066788)
		(width 0.381)
		(layer "F.Cu")
		(net "GND")
	)
	(segment
		(start 56.398414 -232.166668)
		(end 57.503314 -232.166668)
		(width 0.381)
		(layer "F.Cu")
		(net "GND")
	)
	(segment
		(start 337.49488 -250.15571)
		(end 337.49488 -249.620024)
		(width 0.2032)
		(layer "F.Cu")
		(net "GND")
	)
	(segment
		(start 96.133666 -237.133892)
		(end 96.133412 -237.133638)
		(width 0.2032)
		(layer "F.Cu")
		(net "GND")
	)
	(segment
		(start 169.352214 -239.81664)
		(end 170.457114 -239.81664)
		(width 0.381)
		(layer "F.Cu")
		(net "GND")
	)
	(segment
		(start 134.665466 -220.855794)
		(end 134.665466 -220.320108)
		(width 0.2032)
		(layer "F.Cu")
		(net "GND")
	)
	(segment
		(start 90.964512 -244.458744)
		(end 90.964766 -244.45849)
		(width 0.2032)
		(layer "F.Cu")
		(net "GND")
	)
	(segment
		(start 312.987182 -230.466646)
		(end 314.092082 -230.466646)
		(width 0.381)
		(layer "F.Cu")
		(net "GND")
	)
	(segment
		(start 126.89078 -107.895898)
		(end 127.52578 -107.895898)
		(width 0.3556)
		(layer "F.Cu")
		(net "GND")
	)
	(segment
		(start 111.640112 -218.414346)
		(end 111.640112 -217.878406)
		(width 0.2032)
		(layer "F.Cu")
		(net "GND")
	)
	(segment
		(start 158.813246 -229.616762)
		(end 159.918146 -229.616762)
		(width 0.381)
		(layer "F.Cu")
		(net "GND")
	)
	(segment
		(start 108.930694 -277.800562)
		(end 108.930694 -278.336502)
		(width 0.254)
		(layer "F.Cu")
		(net "GND")
	)
	(segment
		(start 22.123146 -261.916672)
		(end 23.228046 -261.916672)
		(width 0.381)
		(layer "F.Cu")
		(net "GND")
	)
	(segment
		(start 38.315646 -203.266802)
		(end 37.210746 -203.266802)
		(width 0.381)
		(layer "F.Cu")
		(net "GND")
	)
	(segment
		(start 347.472762 -277.800562)
		(end 347.472762 -278.336248)
		(width 0.2032)
		(layer "F.Cu")
		(net "GND")
	)
	(segment
		(start 380.725934 -214.344758)
		(end 380.725934 -213.732618)
		(width 0.254)
		(layer "F.Cu")
		(net "GND")
	)
	(segment
		(start 158.813246 -244.916706)
		(end 159.918146 -244.916706)
		(width 0.381)
		(layer "F.Cu")
		(net "GND")
	)
	(segment
		(start 372.847362 -282.683966)
		(end 372.847616 -282.68422)
		(width 0.254)
		(layer "F.Cu")
		(net "GND")
	)
	(segment
		(start 170.457114 -238.116618)
		(end 171.795186 -238.116618)
		(width 0.381)
		(layer "F.Cu")
		(net "GND")
	)
	(segment
		(start 27.6352 -408.0764)
		(end 27.9908 -407.7208)
		(width 0.3556)
		(layer "F.Cu")
		(net "GND")
	)
	(segment
		(start 102.355142 -339.294724)
		(end 102.355142 -338.690712)
		(width 0.381)
		(layer "F.Cu")
		(net "GND")
	)
	(segment
		(start 135.135112 -242.830858)
		(end 135.135112 -242.295172)
		(width 0.2032)
		(layer "F.Cu")
		(net "GND")
	)
	(segment
		(start 452.016114 -292.516814)
		(end 453.121014 -292.516814)
		(width 0.381)
		(layer "F.Cu")
		(net "GND")
	)
	(segment
		(start 328.648822 -60.442348)
		(end 328.648822 -60.327032)
		(width 0.254)
		(layer "F.Cu")
		(net "GND")
	)
	(segment
		(start 301.343314 -225.36658)
		(end 302.448214 -225.36658)
		(width 0.381)
		(layer "F.Cu")
		(net "GND")
	)
	(segment
		(start 345.123516 -262.336534)
		(end 345.123516 -262.872474)
		(width 0.2032)
		(layer "F.Cu")
		(net "GND")
	)
	(segment
		(start 428.279814 -199.01662)
		(end 429.384714 -199.01662)
		(width 0.381)
		(layer "F.Cu")
		(net "GND")
	)
	(segment
		(start 416.556952 -8.320024)
		(end 416.556952 -9.424924)
		(width 0.3556)
		(layer "F.Cu")
		(net "GND")
	)
	(segment
		(start 208.176114 -249.166634)
		(end 209.281014 -249.166634)
		(width 0.381)
		(layer "F.Cu")
		(net "GND")
	)
	(segment
		(start 296.794682 -305.266598)
		(end 297.899582 -305.266598)
		(width 0.381)
		(layer "F.Cu")
		(net "GND")
	)
	(segment
		(start 353.001834 -229.808532)
		(end 353.001834 -229.272846)
		(width 0.2032)
		(layer "F.Cu")
		(net "GND")
	)
	(segment
		(start 297.899582 -301.01667)
		(end 299.004482 -301.01667)
		(width 0.381)
		(layer "F.Cu")
		(net "GND")
	)
	(segment
		(start 335.725262 -288.916872)
		(end 335.725008 -288.917126)
		(width 0.254)
		(layer "F.Cu")
		(net "GND")
	)
	(segment
		(start 157.708346 -197.316598)
		(end 158.813246 -197.316598)
		(width 0.381)
		(layer "F.Cu")
		(net "GND")
	)
	(segment
		(start 188.988446 -281.466798)
		(end 190.093346 -281.466798)
		(width 0.381)
		(layer "F.Cu")
		(net "GND")
	)
	(segment
		(start 25.47366 -430.875948)
		(end 26.02992 -430.875948)
		(width 0.3556)
		(layer "F.Cu")
		(net "GND")
	)
	(segment
		(start 409.637992 -216.90457)
		(end 409.675838 -216.866724)
		(width 0.381)
		(layer "F.Cu")
		(net "GND")
	)
	(segment
		(start 425.940982 -241.516662)
		(end 427.045882 -241.516662)
		(width 0.381)
		(layer "F.Cu")
		(net "GND")
	)
	(segment
		(start 19.784314 -200.716642)
		(end 18.679414 -200.716642)
		(width 0.381)
		(layer "F.Cu")
		(net "GND")
	)
	(segment
		(start 374.257316 -256.361184)
		(end 374.257062 -256.361438)
		(width 0.254)
		(layer "F.Cu")
		(net "GND")
	)
	(segment
		(start 436.928514 -258.516628)
		(end 438.033414 -258.516628)
		(width 0.381)
		(layer "F.Cu")
		(net "GND")
	)
	(segment
		(start 43.85691 -10.16508)
		(end 43.85691 -11.26998)
		(width 0.3556)
		(layer "F.Cu")
		(net "GND")
	)
	(segment
		(start 196.532246 -270.416782)
		(end 197.637146 -270.416782)
		(width 0.381)
		(layer "F.Cu")
		(net "GND")
	)
	(segment
		(start 11.135614 -238.116618)
		(end 12.240514 -238.116618)
		(width 0.381)
		(layer "F.Cu")
		(net "GND")
	)
	(segment
		(start 382.245362 -272.917158)
		(end 382.245616 -273.453098)
		(width 0.2032)
		(layer "F.Cu")
		(net "GND")
	)
	(segment
		(start 406.753314 -212.616796)
		(end 407.858214 -212.616796)
		(width 0.381)
		(layer "F.Cu")
		(net "GND")
	)
	(segment
		(start 458.32014 -382.15443)
		(end 458.867764 -381.606806)
		(width 0.3556)
		(layer "F.Cu")
		(net "GND")
	)
	(segment
		(start 453.121014 -290.816792)
		(end 452.016114 -290.816792)
		(width 0.381)
		(layer "F.Cu")
		(net "GND")
	)
	(segment
		(start 106.941112 -216.250774)
		(end 106.941366 -216.25052)
		(width 0.254)
		(layer "F.Cu")
		(net "GND")
	)
	(segment
		(start 345.143836 -59.505596)
		(end 344.903552 -59.265312)
		(width 0.2032)
		(layer "F.Cu")
		(net "GND")
	)
	(segment
		(start 365.21898 -229.808786)
		(end 365.219234 -229.808532)
		(width 0.2032)
		(layer "F.Cu")
		(net "GND")
	)
	(segment
		(start 98.53295 -413.273748)
		(end 98.6028 -413.343598)
		(width 0.3556)
		(layer "F.Cu")
		(net "GND")
	)
	(segment
		(start 304.197258 -33.746186)
		(end 303.600612 -34.342832)
		(width 0.3556)
		(layer "F.Cu")
		(net "GND")
	)
	(segment
		(start 452.016114 -246.616728)
		(end 450.911214 -246.616728)
		(width 0.381)
		(layer "F.Cu")
		(net "GND")
	)
	(segment
		(start 339.014562 -273.452844)
		(end 339.014816 -273.453098)
		(width 0.2032)
		(layer "F.Cu")
		(net "GND")
	)
	(segment
		(start 300.238414 -233.016806)
		(end 301.343314 -233.016806)
		(width 0.381)
		(layer "F.Cu")
		(net "GND")
	)
	(segment
		(start 256.080514 -238.966756)
		(end 257.185414 -238.966756)
		(width 0.381)
		(layer "F.Cu")
		(net "GND")
	)
	(segment
		(start 117.22608 -122.532648)
		(end 117.22608 -123.148598)
		(width 0.3556)
		(layer "F.Cu")
		(net "GND")
	)
	(segment
		(start 161.757614 -271.266666)
		(end 162.913314 -271.266666)
		(width 0.381)
		(layer "F.Cu")
		(net "GND")
	)
	(segment
		(start 42.415714 -297.616626)
		(end 41.310814 -297.616626)
		(width 0.381)
		(layer "F.Cu")
		(net "GND")
	)
	(segment
		(start 202.971146 -272.116804)
		(end 204.076046 -272.116804)
		(width 0.381)
		(layer "F.Cu")
		(net "GND")
	)
	(segment
		(start 43.520614 -228.766624)
		(end 42.415714 -228.766624)
		(width 0.381)
		(layer "F.Cu")
		(net "GND")
	)
	(segment
		(start 208.06029 -112.61471)
		(end 208.54924 -112.61471)
		(width 0.3556)
		(layer "F.Cu")
		(net "GND")
	)
	(segment
		(start 19.784314 -278.916638)
		(end 20.889214 -278.916638)
		(width 0.381)
		(layer "F.Cu")
		(net "GND")
	)
	(segment
		(start 377.546362 -261.522718)
		(end 377.546362 -262.058404)
		(width 0.254)
		(layer "F.Cu")
		(net "GND")
	)
	(segment
		(start 104.701594 -277.522178)
		(end 104.701594 -277.522432)
		(width 0.2032)
		(layer "F.Cu")
		(net "GND")
	)
	(segment
		(start 117.604794 -104.213914)
		(end 117.35308 -104.465628)
		(width 0.3556)
		(layer "F.Cu")
		(net "GND")
	)
	(segment
		(start 101.302566 -220.041724)
		(end 101.302566 -219.506038)
		(width 0.254)
		(layer "F.Cu")
		(net "GND")
	)
	(segment
		(start 278.711914 -220.266768)
		(end 279.816814 -220.266768)
		(width 0.381)
		(layer "F.Cu")
		(net "GND")
	)
	(segment
		(start 123.387866 -214.344758)
		(end 123.387866 -213.732618)
		(width 0.254)
		(layer "F.Cu")
		(net "GND")
	)
	(segment
		(start 186.649614 -306.96662)
		(end 185.544714 -306.96662)
		(width 0.381)
		(layer "F.Cu")
		(net "GND")
	)
	(segment
		(start 338.90458 -216.78646)
		(end 338.90458 -216.250774)
		(width 0.254)
		(layer "F.Cu")
		(net "GND")
	)
	(segment
		(start 370.38788 -228.994716)
		(end 370.38788 -228.45903)
		(width 0.254)
		(layer "F.Cu")
		(net "GND")
	)
	(segment
		(start 254.975614 -233.016806)
		(end 256.080514 -233.016806)
		(width 0.381)
		(layer "F.Cu")
		(net "GND")
	)
	(segment
		(start 92.844112 -226.553268)
		(end 92.844112 -226.017582)
		(width 0.254)
		(layer "F.Cu")
		(net "GND")
	)
	(segment
		(start 335.725262 -255.825498)
		(end 335.725262 -256.361438)
		(width 0.2032)
		(layer "F.Cu")
		(net "GND")
	)
	(segment
		(start 127.726694 -266.405868)
		(end 127.726948 -266.941808)
		(width 0.2032)
		(layer "F.Cu")
		(net "GND")
	)
	(segment
		(start 410.853382 -312.91657)
		(end 412.160974 -312.91657)
		(width 0.381)
		(layer "F.Cu")
		(net "GND")
	)
	(segment
		(start 189.28588 -134.095998)
		(end 189.28588 -134.711948)
		(width 0.3556)
		(layer "F.Cu")
		(net "GND")
	)
	(segment
		(start 22.123146 -225.36658)
		(end 23.228046 -225.36658)
		(width 0.381)
		(layer "F.Cu")
		(net "GND")
	)
	(segment
		(start 432.379882 -207.51673)
		(end 433.484782 -207.51673)
		(width 0.381)
		(layer "F.Cu")
		(net "GND")
	)
	(segment
		(start 378.846334 -224.111566)
		(end 378.846334 -223.575626)
		(width 0.2032)
		(layer "F.Cu")
		(net "GND")
	)
	(segment
		(start 413.192214 -317.166752)
		(end 414.297114 -317.166752)
		(width 0.381)
		(layer "F.Cu")
		(net "GND")
	)
	(segment
		(start 350.762316 -273.730974)
		(end 350.762316 -274.26666)
		(width 0.2032)
		(layer "F.Cu")
		(net "GND")
	)
	(segment
		(start 94.833694 -266.405868)
		(end 94.833948 -266.406122)
		(width 0.2032)
		(layer "F.Cu")
		(net "GND")
	)
	(segment
		(start 105.641648 -270.475456)
		(end 105.641394 -270.47571)
		(width 0.254)
		(layer "F.Cu")
		(net "GND")
	)
	(segment
		(start 48.854614 -247.466612)
		(end 49.959514 -247.466612)
		(width 0.381)
		(layer "F.Cu")
		(net "GND")
	)
	(segment
		(start 419.796468 -219.41663)
		(end 418.397182 -219.41663)
		(width 0.381)
		(layer "F.Cu")
		(net "GND")
	)
	(segment
		(start 96.17583 -54.066948)
		(end 95.56623 -54.066948)
		(width 0.3556)
		(layer "F.Cu")
		(net "GND")
	)
	(segment
		(start 366.58677 -404.38197)
		(end 366.58677 -403.957028)
		(width 0.3556)
		(layer "F.Cu")
		(net "GND")
	)
	(segment
		(start 210.514946 -216.016586)
		(end 211.619846 -216.016586)
		(width 0.381)
		(layer "F.Cu")
		(net "GND")
	)
	(segment
		(start 428.279814 -248.31675)
		(end 429.384714 -248.31675)
		(width 0.381)
		(layer "F.Cu")
		(net "GND")
	)
	(segment
		(start 11.135614 -295.916604)
		(end 12.240514 -295.916604)
		(width 0.381)
		(layer "F.Cu")
		(net "GND")
	)
	(segment
		(start 422.945814 -295.06672)
		(end 421.840914 -295.06672)
		(width 0.381)
		(layer "F.Cu")
		(net "GND")
	)
	(segment
		(start 129.026666 -224.111566)
		(end 129.026666 -223.575626)
		(width 0.2032)
		(layer "F.Cu")
		(net "GND")
	)
	(segment
		(start 419.502082 -262.76681)
		(end 418.397182 -262.76681)
		(width 0.381)
		(layer "F.Cu")
		(net "GND")
	)
	(segment
		(start 165.252146 -246.616728)
		(end 166.357046 -246.616728)
		(width 0.381)
		(layer "F.Cu")
		(net "GND")
	)
	(segment
		(start 287.360614 -240.666778)
		(end 286.255714 -240.666778)
		(width 0.381)
		(layer "F.Cu")
		(net "GND")
	)
	(segment
		(start 363.046518 -357.91775)
		(end 363.656118 -357.91775)
		(width 0.381)
		(layer "F.Cu")
		(net "GND")
	)
	(segment
		(start 460.664814 -240.666778)
		(end 459.559914 -240.666778)
		(width 0.381)
		(layer "F.Cu")
		(net "GND")
	)
	(segment
		(start 449.677282 -286.56661)
		(end 448.572382 -286.56661)
		(width 0.381)
		(layer "F.Cu")
		(net "GND")
	)
	(segment
		(start 15.684246 -220.266768)
		(end 16.789146 -220.266768)
		(width 0.381)
		(layer "F.Cu")
		(net "GND")
	)
	(segment
		(start 59.842146 -227.066602)
		(end 60.947046 -227.066602)
		(width 0.381)
		(layer "F.Cu")
		(net "GND")
	)
	(segment
		(start 52.500276 -162.016186)
		(end 52.023264 -161.539174)
		(width 0.2032)
		(layer "F.Cu")
		(net "GND")
	)
	(segment
		(start 273.491706 -129.44983)
		(end 273.491706 -128.641094)
		(width 0.3556)
		(layer "F.Cu")
		(net "GND")
	)
	(segment
		(start 51.064414 -200.716642)
		(end 49.959514 -200.716642)
		(width 0.381)
		(layer "F.Cu")
		(net "GND")
	)
	(segment
		(start 381.775716 -278.614378)
		(end 381.775462 -279.150318)
		(width 0.254)
		(layer "F.Cu")
		(net "GND")
	)
	(segment
		(start 32.337502 -164.364162)
		(end 32.337502 -165.04031)
		(width 0.381)
		(layer "F.Cu")
		(net "GND")
	)
	(segment
		(start 22.147022 -11.26998)
		(end 22.147022 -12.37488)
		(width 0.3556)
		(layer "F.Cu")
		(net "GND")
	)
	(segment
		(start 289.250882 -312.91657)
		(end 290.355782 -312.91657)
		(width 0.381)
		(layer "F.Cu")
		(net "GND")
	)
	(segment
		(start 162.912044 -427.477682)
		(end 162.912044 -428.569882)
		(width 0.3556)
		(layer "F.Cu")
		(net "GND")
	)
	(segment
		(start 445.577214 -203.266802)
		(end 444.472314 -203.266802)
		(width 0.381)
		(layer "F.Cu")
		(net "GND")
	)
	(segment
		(start 110.340648 -285.125414)
		(end 110.340648 -285.6611)
		(width 0.254)
		(layer "F.Cu")
		(net "GND")
	)
	(segment
		(start 337.900264 -60.284106)
		(end 337.900264 -59.265312)
		(width 0.1016)
		(layer "F.Cu")
		(net "GND")
	)
	(segment
		(start 342.19388 -233.877866)
		(end 342.19388 -233.34218)
		(width 0.2032)
		(layer "F.Cu")
		(net "GND")
	)
	(segment
		(start 459.559914 -244.916706)
		(end 458.455014 -244.916706)
		(width 0.381)
		(layer "F.Cu")
		(net "GND")
	)
	(segment
		(start 135.714994 -280.242264)
		(end 135.714994 -280.778204)
		(width 0.254)
		(layer "F.Cu")
		(net "GND")
	)
	(segment
		(start 199.527414 -204.116686)
		(end 200.632314 -204.116686)
		(width 0.381)
		(layer "F.Cu")
		(net "GND")
	)
	(segment
		(start 425.940982 -271.266666)
		(end 427.045882 -271.266666)
		(width 0.381)
		(layer "F.Cu")
		(net "GND")
	)
	(segment
		(start 185.62828 -21.351748)
		(end 185.399172 -21.580856)
		(width 0.4572)
		(layer "F.Cu")
		(net "GND")
	)
	(segment
		(start 59.842146 -223.666558)
		(end 60.947046 -223.666558)
		(width 0.381)
		(layer "F.Cu")
		(net "GND")
	)
	(segment
		(start 96.133412 -235.505752)
		(end 96.133412 -234.970066)
		(width 0.2032)
		(layer "F.Cu")
		(net "GND")
	)
	(segment
		(start 211.1248 -97.6376)
		(end 210.96605 -97.6376)
		(width 0.3556)
		(layer "F.Cu")
		(net "GND")
	)
	(segment
		(start 162.913314 -288.266632)
		(end 163.967414 -288.266632)
		(width 0.381)
		(layer "F.Cu")
		(net "GND")
	)
	(segment
		(start 456.116182 -294.216582)
		(end 455.011282 -294.216582)
		(width 0.381)
		(layer "F.Cu")
		(net "GND")
	)
	(segment
		(start 345.554554 -44.948602)
		(end 345.15171 -44.349162)
		(width 0.2032)
		(layer "F.Cu")
		(net "GND")
	)
	(segment
		(start 385.424934 -243.644928)
		(end 384.485134 -243.108988)
		(width 0.254)
		(layer "F.Cu")
		(net "GND")
	)
	(segment
		(start 296.794682 -280.61666)
		(end 297.899582 -280.61666)
		(width 0.381)
		(layer "F.Cu")
		(net "GND")
	)
	(segment
		(start 63.942214 -247.466612)
		(end 65.047114 -247.466612)
		(width 0.381)
		(layer "F.Cu")
		(net "GND")
	)
	(segment
		(start 32.361378 -100.602034)
		(end 31.751778 -100.602034)
		(width 0.3556)
		(layer "F.Cu")
		(net "GND")
	)
	(segment
		(start 347.003116 -257.45313)
		(end 347.003116 -257.98907)
		(width 0.2032)
		(layer "F.Cu")
		(net "GND")
	)
	(segment
		(start 186.649614 -289.966654)
		(end 185.544714 -289.966654)
		(width 0.381)
		(layer "F.Cu")
		(net "GND")
	)
	(segment
		(start 423.804842 -387.314948)
		(end 423.195242 -387.314948)
		(width 0.381)
		(layer "F.Cu")
		(net "GND")
	)
	(segment
		(start 358.160828 -335.886552)
		(end 358.506268 -335.541112)
		(width 0.2032)
		(layer "F.Cu")
		(net "GND")
	)
	(segment
		(start 448.572382 -238.116618)
		(end 447.467482 -238.116618)
		(width 0.381)
		(layer "F.Cu")
		(net "GND")
	)
	(segment
		(start 176.896014 -272.966688)
		(end 178.000914 -272.966688)
		(width 0.381)
		(layer "F.Cu")
		(net "GND")
	)
	(segment
		(start 334.315562 -264.778236)
		(end 334.785462 -264.50036)
		(width 0.254)
		(layer "F.Cu")
		(net "GND")
	)
	(segment
		(start 373.787162 -257.175254)
		(end 373.787162 -256.639314)
		(width 0.2032)
		(layer "F.Cu")
		(net "GND")
	)
	(segment
		(start 123.497848 -278.614378)
		(end 123.497848 -279.150318)
		(width 0.2032)
		(layer "F.Cu")
		(net "GND")
	)
	(segment
		(start 422.750996 -364.486952)
		(end 422.750996 -364.257336)
		(width 0.2032)
		(layer "F.Cu")
		(net "GND")
	)
	(segment
		(start 45.859446 -234.716574)
		(end 46.964346 -234.716574)
		(width 0.381)
		(layer "F.Cu")
		(net "GND")
	)
	(segment
		(start 136.075166 -224.925382)
		(end 136.075166 -224.389442)
		(width 0.254)
		(layer "F.Cu")
		(net "GND")
	)
	(segment
		(start 101.302566 -236.319568)
		(end 101.302566 -235.783882)
		(width 0.2032)
		(layer "F.Cu")
		(net "GND")
	)
	(segment
		(start 214.615014 -196.466714)
		(end 215.719914 -196.466714)
		(width 0.381)
		(layer "F.Cu")
		(net "GND")
	)
	(segment
		(start 339.014562 -277.800562)
		(end 339.014562 -278.336502)
		(width 0.2032)
		(layer "F.Cu")
		(net "GND")
	)
	(segment
		(start 459.559914 -251.716794)
		(end 458.455014 -251.716794)
		(width 0.381)
		(layer "F.Cu")
		(net "GND")
	)
	(segment
		(start 294.904414 -236.416596)
		(end 293.799514 -236.416596)
		(width 0.381)
		(layer "F.Cu")
		(net "GND")
	)
	(segment
		(start 364.389162 -287.567116)
		(end 364.389162 -288.102802)
		(width 0.254)
		(layer "F.Cu")
		(net "GND")
	)
	(segment
		(start 297.899582 -308.666642)
		(end 299.004482 -308.666642)
		(width 0.381)
		(layer "F.Cu")
		(net "GND")
	)
	(segment
		(start 378.84608 -235.505752)
		(end 378.84608 -234.970066)
		(width 0.2032)
		(layer "F.Cu")
		(net "GND")
	)
	(segment
		(start 305.659282 -435.596538)
		(end 306.017422 -435.596538)
		(width 0.3556)
		(layer "F.Cu")
		(net "GND")
	)
	(segment
		(start 32.361378 -98.570034)
		(end 31.751778 -98.570034)
		(width 0.3556)
		(layer "F.Cu")
		(net "GND")
	)
	(segment
		(start 184.439814 -238.116618)
		(end 185.544714 -238.116618)
		(width 0.381)
		(layer "F.Cu")
		(net "GND")
	)
	(segment
		(start 100.942648 -260.708902)
		(end 100.942648 -261.244588)
		(width 0.254)
		(layer "F.Cu")
		(net "GND")
	)
	(segment
		(start 289.250882 -241.516662)
		(end 290.355782 -241.516662)
		(width 0.381)
		(layer "F.Cu")
		(net "GND")
	)
	(segment
		(start 282.811982 -233.86669)
		(end 283.916882 -233.86669)
		(width 0.381)
		(layer "F.Cu")
		(net "GND")
	)
	(segment
		(start 207.071214 -230.466646)
		(end 208.176114 -230.466646)
		(width 0.381)
		(layer "F.Cu")
		(net "GND")
	)
	(segment
		(start 278.711914 -214.316564)
		(end 279.816814 -214.316564)
		(width 0.381)
		(layer "F.Cu")
		(net "GND")
	)
	(segment
		(start 263.624314 -233.016806)
		(end 264.729214 -233.016806)
		(width 0.381)
		(layer "F.Cu")
		(net "GND")
	)
	(segment
		(start 211.619846 -287.416748)
		(end 210.514946 -287.416748)
		(width 0.381)
		(layer "F.Cu")
		(net "GND")
	)
	(segment
		(start 200.632314 -288.266632)
		(end 201.737214 -288.266632)
		(width 0.381)
		(layer "F.Cu")
		(net "GND")
	)
	(segment
		(start 38.315646 -223.666558)
		(end 37.210746 -223.666558)
		(width 0.381)
		(layer "F.Cu")
		(net "GND")
	)
	(segment
		(start 348.772734 -248.528078)
		(end 348.77248 -248.527824)
		(width 0.2032)
		(layer "F.Cu")
		(net "GND")
	)
	(segment
		(start 15.684246 -315.46673)
		(end 16.789146 -315.46673)
		(width 0.381)
		(layer "F.Cu")
		(net "GND")
	)
	(segment
		(start 375.55678 -223.297496)
		(end 375.55678 -222.76181)
		(width 0.254)
		(layer "F.Cu")
		(net "GND")
	)
	(segment
		(start 195.427346 -242.3668)
		(end 196.532246 -242.3668)
		(width 0.381)
		(layer "F.Cu")
		(net "GND")
	)
	(segment
		(start 119.158766 -228.180646)
		(end 119.158766 -227.64496)
		(width 0.254)
		(layer "F.Cu")
		(net "GND")
	)
	(segment
		(start 311.882282 -200.716642)
		(end 312.987182 -200.716642)
		(width 0.381)
		(layer "F.Cu")
		(net "GND")
	)
	(segment
		(start 432.379882 -289.966654)
		(end 433.484782 -289.966654)
		(width 0.381)
		(layer "F.Cu")
		(net "GND")
	)
	(segment
		(start 439.923682 -233.86669)
		(end 441.028582 -233.86669)
		(width 0.381)
		(layer "F.Cu")
		(net "GND")
	)
	(segment
		(start 262.519414 -251.716794)
		(end 263.624314 -251.716794)
		(width 0.381)
		(layer "F.Cu")
		(net "GND")
	)
	(segment
		(start 214.615014 -250.866656)
		(end 215.719914 -250.866656)
		(width 0.381)
		(layer "F.Cu")
		(net "GND")
	)
	(segment
		(start 110.340648 -285.6611)
		(end 110.340394 -285.661354)
		(width 0.254)
		(layer "F.Cu")
		(net "GND")
	)
	(segment
		(start 107.066842 -96.96704)
		(end 106.431842 -96.96704)
		(width 0.3556)
		(layer "F.Cu")
		(net "GND")
	)
	(segment
		(start 176.555654 -112.97539)
		(end 176.155604 -112.57534)
		(width 0.3556)
		(layer "F.Cu")
		(net "GND")
	)
	(segment
		(start 334.315562 -258.2672)
		(end 334.785462 -257.98907)
		(width 0.254)
		(layer "F.Cu")
		(net "GND")
	)
	(segment
		(start 438.216548 -47.0408)
		(end 438.520586 -46.736762)
		(width 0.3556)
		(layer "F.Cu")
		(net "GND")
	)
	(segment
		(start 414.297114 -276.366732)
		(end 415.605214 -276.366732)
		(width 0.381)
		(layer "F.Cu")
		(net "GND")
	)
	(segment
		(start 378.84608 -243.644674)
		(end 378.84608 -243.108988)
		(width 0.2032)
		(layer "F.Cu")
		(net "GND")
	)
	(segment
		(start 211.619846 -261.916672)
		(end 212.724746 -261.916672)
		(width 0.381)
		(layer "F.Cu")
		(net "GND")
	)
	(segment
		(start 172.997368 -415.250376)
		(end 173.632368 -415.250376)
		(width 0.3556)
		(layer "F.Cu")
		(net "GND")
	)
	(segment
		(start 113.629694 -263.686036)
		(end 113.62944 -263.68629)
		(width 0.254)
		(layer "F.Cu")
		(net "GND")
	)
	(segment
		(start 448.572382 -210.066636)
		(end 447.467482 -210.066636)
		(width 0.381)
		(layer "F.Cu")
		(net "GND")
	)
	(segment
		(start 169.352214 -196.466714)
		(end 170.457114 -196.466714)
		(width 0.381)
		(layer "F.Cu")
		(net "GND")
	)
	(segment
		(start 38.315646 -301.866808)
		(end 37.210746 -301.866808)
		(width 0.381)
		(layer "F.Cu")
		(net "GND")
	)
	(segment
		(start 458.455014 -304.416714)
		(end 459.559914 -304.416714)
		(width 0.381)
		(layer "F.Cu")
		(net "GND")
	)
	(segment
		(start 22.123146 -306.116736)
		(end 23.228046 -306.116736)
		(width 0.381)
		(layer "F.Cu")
		(net "GND")
	)
	(segment
		(start 60.947046 -204.96657)
		(end 62.051946 -204.96657)
		(width 0.381)
		(layer "F.Cu")
		(net "GND")
	)
	(segment
		(start 178.000914 -194.766692)
		(end 176.896014 -194.766692)
		(width 0.381)
		(layer "F.Cu")
		(net "GND")
	)
	(segment
		(start 367.09858 -228.1809)
		(end 367.098834 -228.180646)
		(width 0.254)
		(layer "F.Cu")
		(net "GND")
	)
	(segment
		(start 128.196848 -287.288986)
		(end 128.196594 -287.28924)
		(width 0.254)
		(layer "F.Cu")
		(net "GND")
	)
	(segment
		(start 424.836082 -247.466612)
		(end 425.940982 -247.466612)
		(width 0.381)
		(layer "F.Cu")
		(net "GND")
	)
	(segment
		(start 307.782214 -225.36658)
		(end 308.887114 -225.36658)
		(width 0.381)
		(layer "F.Cu")
		(net "GND")
	)
	(segment
		(start 181.14518 -358.698292)
		(end 180.82133 -358.698292)
		(width 0.381)
		(layer "F.Cu")
		(net "GND")
	)
	(segment
		(start 178.000914 -245.76659)
		(end 176.896014 -245.76659)
		(width 0.381)
		(layer "F.Cu")
		(net "GND")
	)
	(segment
		(start 297.899582 -286.56661)
		(end 299.004482 -286.56661)
		(width 0.381)
		(layer "F.Cu")
		(net "GND")
	)
	(segment
		(start 413.192214 -289.11677)
		(end 414.297114 -289.11677)
		(width 0.381)
		(layer "F.Cu")
		(net "GND")
	)
	(segment
		(start 7.495286 -101.125528)
		(end 7.495286 -101.738938)
		(width 0.3556)
		(layer "F.Cu")
		(net "GND")
	)
	(segment
		(start 8.140446 -227.066602)
		(end 9.245346 -227.066602)
		(width 0.381)
		(layer "F.Cu")
		(net "GND")
	)
	(segment
		(start 304.338482 -271.266666)
		(end 305.443382 -271.266666)
		(width 0.381)
		(layer "F.Cu")
		(net "GND")
	)
	(segment
		(start 279.262078 -416.88385)
		(end 279.262078 -416.27425)
		(width 0.3556)
		(layer "F.Cu")
		(net "GND")
	)
	(segment
		(start 204.076046 -273.816572)
		(end 205.180946 -273.816572)
		(width 0.381)
		(layer "F.Cu")
		(net "GND")
	)
	(segment
		(start 256.080514 -283.166566)
		(end 257.185414 -283.166566)
		(width 0.381)
		(layer "F.Cu")
		(net "GND")
	)
	(segment
		(start 419.502082 -266.1666)
		(end 418.397182 -266.1666)
		(width 0.381)
		(layer "F.Cu")
		(net "GND")
	)
	(segment
		(start 334.205834 -236.319822)
		(end 334.675734 -236.597952)
		(width 0.2032)
		(layer "F.Cu")
		(net "GND")
	)
	(segment
		(start 123.497848 -282.405582)
		(end 123.497594 -282.405836)
		(width 0.254)
		(layer "F.Cu")
		(net "GND")
	)
	(segment
		(start 172.795946 -248.31675)
		(end 173.900846 -248.31675)
		(width 0.381)
		(layer "F.Cu")
		(net "GND")
	)
	(segment
		(start 63.942214 -215.166702)
		(end 65.047114 -215.166702)
		(width 0.381)
		(layer "F.Cu")
		(net "GND")
	)
	(segment
		(start 39.420546 -251.716794)
		(end 38.315646 -251.716794)
		(width 0.381)
		(layer "F.Cu")
		(net "GND")
	)
	(segment
		(start 63.942214 -232.166668)
		(end 65.047114 -232.166668)
		(width 0.381)
		(layer "F.Cu")
		(net "GND")
	)
	(segment
		(start 373.207534 -230.622602)
		(end 373.207534 -230.086662)
		(width 0.2032)
		(layer "F.Cu")
		(net "GND")
	)
	(segment
		(start 421.15359 -163.077144)
		(end 421.15359 -162.435794)
		(width 0.381)
		(layer "F.Cu")
		(net "GND")
	)
	(segment
		(start 285.150814 -292.516814)
		(end 286.255714 -292.516814)
		(width 0.381)
		(layer "F.Cu")
		(net "GND")
	)
	(segment
		(start 425.96689 -8.320024)
		(end 425.96689 -7.215124)
		(width 0.3556)
		(layer "F.Cu")
		(net "GND")
	)
	(segment
		(start 29.666946 -248.31675)
		(end 30.771846 -248.31675)
		(width 0.381)
		(layer "F.Cu")
		(net "GND")
	)
	(segment
		(start 316.523116 -59.299348)
		(end 316.996572 -59.299348)
		(width 0.381)
		(layer "F.Cu")
		(net "GND")
	)
	(segment
		(start 158.813246 -270.416782)
		(end 157.708346 -270.416782)
		(width 0.381)
		(layer "F.Cu")
		(net "GND")
	)
	(segment
		(start 180.339746 -268.71676)
		(end 181.444646 -268.71676)
		(width 0.381)
		(layer "F.Cu")
		(net "GND")
	)
	(segment
		(start 337.02498 -214.622888)
		(end 337.024726 -214.622634)
		(width 0.2032)
		(layer "F.Cu")
		(net "GND")
	)
	(segment
		(start 271.168114 -311.216802)
		(end 270.063214 -311.216802)
		(width 0.381)
		(layer "F.Cu")
		(net "GND")
	)
	(segment
		(start 339.484716 -271.011142)
		(end 339.484462 -271.011396)
		(width 0.2032)
		(layer "F.Cu")
		(net "GND")
	)
	(segment
		(start 194.193414 -226.216718)
		(end 193.088514 -226.216718)
		(width 0.381)
		(layer "F.Cu")
		(net "GND")
	)
	(segment
		(start 364.499652 -391.138156)
		(end 363.990382 -391.138156)
		(width 0.3556)
		(layer "F.Cu")
		(net "GND")
	)
	(segment
		(start 88.255094 -262.058658)
		(end 88.255094 -261.522718)
		(width 0.2032)
		(layer "F.Cu")
		(net "GND")
	)
	(segment
		(start 428.279814 -203.266802)
		(end 429.384714 -203.266802)
		(width 0.381)
		(layer "F.Cu")
		(net "GND")
	)
	(segment
		(start 262.519414 -287.416748)
		(end 263.624314 -287.416748)
		(width 0.381)
		(layer "F.Cu")
		(net "GND")
	)
	(segment
		(start 334.315562 -281.05608)
		(end 334.315562 -281.59202)
		(width 0.2032)
		(layer "F.Cu")
		(net "GND")
	)
	(segment
		(start 382.245362 -260.430518)
		(end 382.245616 -260.430772)
		(width 0.2032)
		(layer "F.Cu")
		(net "GND")
	)
	(segment
		(start 100.472494 -285.939484)
		(end 100.472494 -286.475424)
		(width 0.2032)
		(layer "F.Cu")
		(net "GND")
	)
	(segment
		(start 392.543538 -39.63289)
		(end 392.563858 -39.61257)
		(width 0.3556)
		(layer "F.Cu")
		(net "GND")
	)
	(segment
		(start 110.340648 -284.033468)
		(end 110.340394 -284.033722)
		(width 0.254)
		(layer "F.Cu")
		(net "GND")
	)
	(segment
		(start 59.626246 -285.716726)
		(end 60.947046 -285.716726)
		(width 0.381)
		(layer "F.Cu")
		(net "GND")
	)
	(segment
		(start 48.854614 -194.766692)
		(end 49.959514 -194.766692)
		(width 0.381)
		(layer "F.Cu")
		(net "GND")
	)
	(segment
		(start 449.677282 -264.466578)
		(end 448.572382 -264.466578)
		(width 0.381)
		(layer "F.Cu")
		(net "GND")
	)
	(segment
		(start 193.09588 -114.498628)
		(end 192.63868 -114.041428)
		(width 0.3556)
		(layer "F.Cu")
		(net "GND")
	)
	(segment
		(start 49.917604 -162.280854)
		(end 49.290986 -162.280854)
		(width 0.381)
		(layer "F.Cu")
		(net "GND")
	)
	(segment
		(start 339.484716 -261.244588)
		(end 339.484462 -261.244842)
		(width 0.2032)
		(layer "F.Cu")
		(net "GND")
	)
	(segment
		(start 135.714994 -278.614378)
		(end 135.714994 -279.150318)
		(width 0.2032)
		(layer "F.Cu")
		(net "GND")
	)
	(segment
		(start 256.080514 -273.816572)
		(end 257.185414 -273.816572)
		(width 0.381)
		(layer "F.Cu")
		(net "GND")
	)
	(segment
		(start 89.664794 -286.7533)
		(end 89.664794 -287.28924)
		(width 0.254)
		(layer "F.Cu")
		(net "GND")
	)
	(segment
		(start 27.6352 -408.64155)
		(end 27.6352 -408.0764)
		(width 0.3556)
		(layer "F.Cu")
		(net "GND")
	)
	(segment
		(start 378.37618 -247.714262)
		(end 378.376434 -247.714008)
		(width 0.2032)
		(layer "F.Cu")
		(net "GND")
	)
	(segment
		(start 289.250882 -314.616592)
		(end 290.355782 -314.616592)
		(width 0.381)
		(layer "F.Cu")
		(net "GND")
	)
	(segment
		(start 421.15359 -171.713144)
		(end 421.15359 -171.071794)
		(width 0.381)
		(layer "F.Cu")
		(net "GND")
	)
	(segment
		(start 335.299558 -48.450246)
		(end 336.099658 -48.450246)
		(width 0.2032)
		(layer "F.Cu")
		(net "GND")
	)
	(segment
		(start 215.719914 -258.516628)
		(end 216.824814 -258.516628)
		(width 0.381)
		(layer "F.Cu")
		(net "GND")
	)
	(segment
		(start 15.684246 -203.266802)
		(end 16.789146 -203.266802)
		(width 0.381)
		(layer "F.Cu")
		(net "GND")
	)
	(segment
		(start 272.273014 -199.01662)
		(end 271.168114 -199.01662)
		(width 0.381)
		(layer "F.Cu")
		(net "GND")
	)
	(segment
		(start 176.896014 -278.916638)
		(end 178.000914 -278.916638)
		(width 0.381)
		(layer "F.Cu")
		(net "GND")
	)
	(segment
		(start 29.666946 -296.766742)
		(end 30.771846 -296.766742)
		(width 0.381)
		(layer "F.Cu")
		(net "GND")
	)
	(segment
		(start 301.343314 -300.166786)
		(end 302.448214 -300.166786)
		(width 0.381)
		(layer "F.Cu")
		(net "GND")
	)
	(segment
		(start 26.63825 -129.380996)
		(end 26.63825 -130.396996)
		(width 0.381)
		(layer "F.Cu")
		(net "GND")
	)
	(segment
		(start 358.160828 -336.115406)
		(end 358.160828 -335.886552)
		(width 0.2032)
		(layer "F.Cu")
		(net "GND")
	)
	(segment
		(start 358.170734 -227.367084)
		(end 358.170734 -226.831144)
		(width 0.2032)
		(layer "F.Cu")
		(net "GND")
	)
	(segment
		(start 34.871914 -216.866724)
		(end 35.976814 -216.866724)
		(width 0.381)
		(layer "F.Cu")
		(net "GND")
	)
	(segment
		(start 14.579346 -225.36658)
		(end 15.684246 -225.36658)
		(width 0.381)
		(layer "F.Cu")
		(net "GND")
	)
	(segment
		(start 90.964512 -223.297496)
		(end 90.964512 -222.76181)
		(width 0.254)
		(layer "F.Cu")
		(net "GND")
	)
	(segment
		(start 107.990894 -272.917158)
		(end 107.990894 -273.452844)
		(width 0.2032)
		(layer "F.Cu")
		(net "GND")
	)
	(segment
		(start 54.42458 -162.713924)
		(end 54.42458 -162.397948)
		(width 0.2032)
		(layer "F.Cu")
		(net "GND")
	)
	(segment
		(start 187.883546 -272.116804)
		(end 188.988446 -272.116804)
		(width 0.381)
		(layer "F.Cu")
		(net "GND")
	)
	(segment
		(start 338.434934 -245.27256)
		(end 338.434934 -244.73662)
		(width 0.2032)
		(layer "F.Cu")
		(net "GND")
	)
	(segment
		(start 373.787162 -253.919482)
		(end 373.787416 -253.919736)
		(width 0.2032)
		(layer "F.Cu")
		(net "GND")
	)
	(segment
		(start 128.556512 -242.295172)
		(end 128.556766 -242.294918)
		(width 0.2032)
		(layer "F.Cu")
		(net "GND")
	)
	(segment
		(start 292.694614 -315.46673)
		(end 293.799514 -315.46673)
		(width 0.381)
		(layer "F.Cu")
		(net "GND")
	)
	(segment
		(start 341.833962 -264.778236)
		(end 341.833962 -265.313922)
		(width 0.2032)
		(layer "F.Cu")
		(net "GND")
	)
	(segment
		(start 38.315646 -210.916774)
		(end 37.210746 -210.916774)
		(width 0.381)
		(layer "F.Cu")
		(net "GND")
	)
	(segment
		(start 296.578782 -294.216582)
		(end 297.899582 -294.216582)
		(width 0.381)
		(layer "F.Cu")
		(net "GND")
	)
	(segment
		(start 342.304116 -284.033468)
		(end 342.303862 -284.033722)
		(width 0.254)
		(layer "F.Cu")
		(net "GND")
	)
	(segment
		(start 413.192214 -309.51678)
		(end 414.297114 -309.51678)
		(width 0.381)
		(layer "F.Cu")
		(net "GND")
	)
	(segment
		(start 439.923682 -282.316682)
		(end 441.028582 -282.316682)
		(width 0.381)
		(layer "F.Cu")
		(net "GND")
	)
	(segment
		(start 190.093346 -268.71676)
		(end 188.988446 -268.71676)
		(width 0.381)
		(layer "F.Cu")
		(net "GND")
	)
	(segment
		(start 278.711914 -212.616796)
		(end 279.816814 -212.616796)
		(width 0.381)
		(layer "F.Cu")
		(net "GND")
	)
	(segment
		(start 375.666762 -276.172676)
		(end 375.667016 -276.708616)
		(width 0.2032)
		(layer "F.Cu")
		(net "GND")
	)
	(segment
		(start 15.684246 -244.916706)
		(end 16.789146 -244.916706)
		(width 0.381)
		(layer "F.Cu")
		(net "GND")
	)
	(segment
		(start 449.677282 -272.966688)
		(end 448.572382 -272.966688)
		(width 0.381)
		(layer "F.Cu")
		(net "GND")
	)
	(segment
		(start 304.338482 -308.666642)
		(end 305.443382 -308.666642)
		(width 0.381)
		(layer "F.Cu")
		(net "GND")
	)
	(segment
		(start 311.882282 -247.466612)
		(end 312.987182 -247.466612)
		(width 0.381)
		(layer "F.Cu")
		(net "GND")
	)
	(segment
		(start 331.881988 -55.498746)
		(end 332.422246 -55.498746)
		(width 0.2032)
		(layer "F.Cu")
		(net "GND")
	)
	(segment
		(start 199.527414 -289.966654)
		(end 200.632314 -289.966654)
		(width 0.381)
		(layer "F.Cu")
		(net "GND")
	)
	(segment
		(start 267.724382 -316.316614)
		(end 268.829282 -316.316614)
		(width 0.381)
		(layer "F.Cu")
		(net "GND")
	)
	(segment
		(start 251.807726 -96.313244)
		(end 251.587 -96.092518)
		(width 0.2032)
		(layer "F.Cu")
		(net "GND")
	)
	(segment
		(start 375.55678 -244.458744)
		(end 375.557034 -244.45849)
		(width 0.2032)
		(layer "F.Cu")
		(net "GND")
	)
	(segment
		(start 448.572382 -215.166702)
		(end 447.467482 -215.166702)
		(width 0.381)
		(layer "F.Cu")
		(net "GND")
	)
	(segment
		(start 186.649614 -308.666642)
		(end 185.544714 -308.666642)
		(width 0.381)
		(layer "F.Cu")
		(net "GND")
	)
	(segment
		(start 121.508266 -220.855794)
		(end 121.508266 -220.319854)
		(width 0.2032)
		(layer "F.Cu")
		(net "GND")
	)
	(segment
		(start 127.616966 -249.341894)
		(end 127.616966 -248.806208)
		(width 0.2032)
		(layer "F.Cu")
		(net "GND")
	)
	(segment
		(start 405.648414 -214.316564)
		(end 406.753314 -214.316564)
		(width 0.381)
		(layer "F.Cu")
		(net "GND")
	)
	(segment
		(start 221.31528 -105.855008)
		(end 220.785944 -106.384344)
		(width 0.3556)
		(layer "F.Cu")
		(net "GND")
	)
	(segment
		(start 277.607014 -214.316564)
		(end 278.711914 -214.316564)
		(width 0.381)
		(layer "F.Cu")
		(net "GND")
	)
	(segment
		(start 129.136648 -286.7533)
		(end 129.136648 -287.288986)
		(width 0.254)
		(layer "F.Cu")
		(net "GND")
	)
	(segment
		(start 382.245362 -274.54479)
		(end 382.245362 -275.080476)
		(width 0.2032)
		(layer "F.Cu")
		(net "GND")
	)
	(segment
		(start 385.534662 -280.242264)
		(end 385.534662 -280.778204)
		(width 0.254)
		(layer "F.Cu")
		(net "GND")
	)
	(segment
		(start 189.861952 -13.600176)
		(end 189.861952 -12.462002)
		(width 0.3556)
		(layer "F.Cu")
		(net "GND")
	)
	(segment
		(start 167.395906 -132.376164)
		(end 168.082722 -132.376164)
		(width 0.3556)
		(layer "F.Cu")
		(net "GND")
	)
	(segment
		(start 405.64689 -11.26998)
		(end 405.64689 -10.16508)
		(width 0.3556)
		(layer "F.Cu")
		(net "GND")
	)
	(segment
		(start 162.913314 -299.316648)
		(end 164.018214 -299.316648)
		(width 0.381)
		(layer "F.Cu")
		(net "GND")
	)
	(segment
		(start 413.192214 -300.166786)
		(end 414.297114 -300.166786)
		(width 0.381)
		(layer "F.Cu")
		(net "GND")
	)
	(segment
		(start 290.355782 -295.916604)
		(end 291.460682 -295.916604)
		(width 0.381)
		(layer "F.Cu")
		(net "GND")
	)
	(segment
		(start 43.520614 -210.066636)
		(end 42.415714 -210.066636)
		(width 0.381)
		(layer "F.Cu")
		(net "GND")
	)
	(segment
		(start 207.071214 -198.166736)
		(end 208.176114 -198.166736)
		(width 0.381)
		(layer "F.Cu")
		(net "GND")
	)
	(segment
		(start 38.315646 -220.266768)
		(end 37.210746 -220.266768)
		(width 0.381)
		(layer "F.Cu")
		(net "GND")
	)
	(segment
		(start 464.764882 -215.166702)
		(end 463.659982 -215.166702)
		(width 0.381)
		(layer "F.Cu")
		(net "GND")
	)
	(segment
		(start 100.362512 -232.528618)
		(end 100.362766 -232.528364)
		(width 0.254)
		(layer "F.Cu")
		(net "GND")
	)
	(segment
		(start 340.424516 -283.497782)
		(end 340.424516 -284.033468)
		(width 0.254)
		(layer "F.Cu")
		(net "GND")
	)
	(segment
		(start 271.168114 -300.166786)
		(end 270.063214 -300.166786)
		(width 0.381)
		(layer "F.Cu")
		(net "GND")
	)
	(segment
		(start 22.123146 -279.766776)
		(end 23.228046 -279.766776)
		(width 0.381)
		(layer "F.Cu")
		(net "GND")
	)
	(segment
		(start 135.106664 -343.391998)
		(end 134.678674 -342.964008)
		(width 0.2032)
		(layer "F.Cu")
		(net "GND")
	)
	(segment
		(start 429.384714 -250.016772)
		(end 430.489614 -250.016772)
		(width 0.381)
		(layer "F.Cu")
		(net "GND")
	)
	(segment
		(start 311.882282 -299.316648)
		(end 312.987182 -299.316648)
		(width 0.381)
		(layer "F.Cu")
		(net "GND")
	)
	(segment
		(start 251.587 -95.849948)
		(end 251.333 -95.595948)
		(width 0.2032)
		(layer "F.Cu")
		(net "GND")
	)
	(segment
		(start 344.183716 -269.383256)
		(end 344.183462 -269.38351)
		(width 0.2032)
		(layer "F.Cu")
		(net "GND")
	)
	(segment
		(start 56.398414 -271.266666)
		(end 57.503314 -271.266666)
		(width 0.381)
		(layer "F.Cu")
		(net "GND")
	)
	(segment
		(start 383.07518 -242.295172)
		(end 383.075434 -242.294918)
		(width 0.2032)
		(layer "F.Cu")
		(net "GND")
	)
	(segment
		(start 344.54338 -223.297496)
		(end 344.54338 -222.76181)
		(width 0.254)
		(layer "F.Cu")
		(net "GND")
	)
	(segment
		(start 180.339746 -265.316716)
		(end 181.444646 -265.316716)
		(width 0.381)
		(layer "F.Cu")
		(net "GND")
	)
	(segment
		(start 312.987182 -247.466612)
		(end 314.092082 -247.466612)
		(width 0.381)
		(layer "F.Cu")
		(net "GND")
	)
	(segment
		(start 100.942648 -287.288986)
		(end 100.942394 -287.28924)
		(width 0.254)
		(layer "F.Cu")
		(net "GND")
	)
	(segment
		(start 57.503314 -226.216718)
		(end 58.608214 -226.216718)
		(width 0.381)
		(layer "F.Cu")
		(net "GND")
	)
	(segment
		(start 126.676912 -220.041978)
		(end 126.677166 -220.041724)
		(width 0.254)
		(layer "F.Cu")
		(net "GND")
	)
	(segment
		(start 185.544714 -241.516662)
		(end 186.649614 -241.516662)
		(width 0.381)
		(layer "F.Cu")
		(net "GND")
	)
	(segment
		(start 96.243394 -265.592306)
		(end 96.243648 -265.592306)
		(width 0.254)
		(layer "F.Cu")
		(net "GND")
	)
	(segment
		(start 44.754546 -208.366614)
		(end 45.859446 -208.366614)
		(width 0.381)
		(layer "F.Cu")
		(net "GND")
	)
	(segment
		(start 296.794682 -301.01667)
		(end 297.899582 -301.01667)
		(width 0.381)
		(layer "F.Cu")
		(net "GND")
	)
	(segment
		(start 106.001566 -229.808532)
		(end 106.001566 -229.272846)
		(width 0.2032)
		(layer "F.Cu")
		(net "GND")
	)
	(segment
		(start 376.966734 -242.017042)
		(end 376.966734 -241.481102)
		(width 0.2032)
		(layer "F.Cu")
		(net "GND")
	)
	(segment
		(start 118.798848 -283.497782)
		(end 118.798848 -284.033468)
		(width 0.254)
		(layer "F.Cu")
		(net "GND")
	)
	(segment
		(start 100.362766 -228.180646)
		(end 100.362766 -227.64496)
		(width 0.2032)
		(layer "F.Cu")
		(net "GND")
	)
	(segment
		(start 347.472762 -262.058404)
		(end 347.473016 -262.058658)
		(width 0.254)
		(layer "F.Cu")
		(net "GND")
	)
	(segment
		(start 137.13079 -253.919736)
		(end 137.124694 -253.919736)
		(width 0.2032)
		(layer "F.Cu")
		(net "GND")
	)
	(segment
		(start 443.367414 -240.666778)
		(end 444.472314 -240.666778)
		(width 0.381)
		(layer "F.Cu")
		(net "GND")
	)
	(segment
		(start 33.767014 -244.066568)
		(end 34.871914 -244.066568)
		(width 0.381)
		(layer "F.Cu")
		(net "GND")
	)
	(segment
		(start 210.514946 -199.01662)
		(end 211.619846 -199.01662)
		(width 0.381)
		(layer "F.Cu")
		(net "GND")
	)
	(segment
		(start 213.369398 -19.769328)
		(end 213.621112 -19.517614)
		(width 0.3556)
		(layer "F.Cu")
		(net "GND")
	)
	(segment
		(start 444.472314 -234.716574)
		(end 445.577214 -234.716574)
		(width 0.381)
		(layer "F.Cu")
		(net "GND")
	)
	(segment
		(start 8.140446 -267.016738)
		(end 9.245346 -267.016738)
		(width 0.381)
		(layer "F.Cu")
		(net "GND")
	)
	(segment
		(start 410.853382 -305.266598)
		(end 411.958282 -305.266598)
		(width 0.381)
		(layer "F.Cu")
		(net "GND")
	)
	(segment
		(start 137.137902 -258.811268)
		(end 137.129774 -258.80314)
		(width 0.254)
		(layer "F.Cu")
		(net "GND")
	)
	(segment
		(start 11.135614 -244.066568)
		(end 12.240514 -244.066568)
		(width 0.381)
		(layer "F.Cu")
		(net "GND")
	)
	(segment
		(start 99.532694 -259.894832)
		(end 99.532694 -260.430518)
		(width 0.2032)
		(layer "F.Cu")
		(net "GND")
	)
	(segment
		(start 19.784314 -301.01667)
		(end 20.889214 -301.01667)
		(width 0.381)
		(layer "F.Cu")
		(net "GND")
	)
	(segment
		(start 121.148094 -289.195002)
		(end 121.148094 -289.807142)
		(width 0.2032)
		(layer "F.Cu")
		(net "GND")
	)
	(segment
		(start 289.250882 -262.76681)
		(end 290.355782 -262.76681)
		(width 0.381)
		(layer "F.Cu")
		(net "GND")
	)
	(segment
		(start 127.257048 -283.497782)
		(end 127.257048 -284.033468)
		(width 0.254)
		(layer "F.Cu")
		(net "GND")
	)
	(segment
		(start 435.823614 -295.06672)
		(end 436.928514 -295.06672)
		(width 0.381)
		(layer "F.Cu")
		(net "GND")
	)
	(segment
		(start 452.016114 -197.316598)
		(end 450.911214 -197.316598)
		(width 0.381)
		(layer "F.Cu")
		(net "GND")
	)
	(segment
		(start 282.811982 -258.516628)
		(end 283.916882 -258.516628)
		(width 0.381)
		(layer "F.Cu")
		(net "GND")
	)
	(segment
		(start 422.945814 -281.466798)
		(end 421.840914 -281.466798)
		(width 0.381)
		(layer "F.Cu")
		(net "GND")
	)
	(segment
		(start 337.49488 -246.900192)
		(end 337.49488 -246.364506)
		(width 0.2032)
		(layer "F.Cu")
		(net "GND")
	)
	(segment
		(start 245.311168 -86.708742)
		(end 245.66245 -86.35746)
		(width 0.3556)
		(layer "F.Cu")
		(net "GND")
	)
	(segment
		(start 53.403246 -216.016586)
		(end 54.508146 -216.016586)
		(width 0.381)
		(layer "F.Cu")
		(net "GND")
	)
	(segment
		(start 199.527414 -241.516662)
		(end 200.632314 -241.516662)
		(width 0.381)
		(layer "F.Cu")
		(net "GND")
	)
	(segment
		(start 19.784314 -262.76681)
		(end 20.889214 -262.76681)
		(width 0.381)
		(layer "F.Cu")
		(net "GND")
	)
	(segment
		(start 88.725248 -267.219938)
		(end 88.725248 -267.755624)
		(width 0.2032)
		(layer "F.Cu")
		(net "GND")
	)
	(segment
		(start 424.836082 -258.516628)
		(end 425.940982 -258.516628)
		(width 0.381)
		(layer "F.Cu")
		(net "GND")
	)
	(segment
		(start 457.221082 -250.866656)
		(end 456.116182 -250.866656)
		(width 0.381)
		(layer "F.Cu")
		(net "GND")
	)
	(segment
		(start 421.840914 -263.616694)
		(end 422.945814 -263.616694)
		(width 0.381)
		(layer "F.Cu")
		(net "GND")
	)
	(segment
		(start 199.527414 -271.266666)
		(end 200.632314 -271.266666)
		(width 0.381)
		(layer "F.Cu")
		(net "GND")
	)
	(segment
		(start 347.363034 -231.436164)
		(end 347.363034 -230.900478)
		(width 0.2032)
		(layer "F.Cu")
		(net "GND")
	)
	(segment
		(start 23.228046 -251.716794)
		(end 24.332946 -251.716794)
		(width 0.381)
		(layer "F.Cu")
		(net "GND")
	)
	(segment
		(start 39.420546 -278.066754)
		(end 38.315646 -278.066754)
		(width 0.381)
		(layer "F.Cu")
		(net "GND")
	)
	(segment
		(start 195.02628 -358.206548)
		(end 194.30873 -358.206548)
		(width 0.3556)
		(layer "F.Cu")
		(net "GND")
	)
	(segment
		(start 196.532246 -307.816758)
		(end 197.637146 -307.816758)
		(width 0.381)
		(layer "F.Cu")
		(net "GND")
	)
	(segment
		(start 179.105814 -215.166702)
		(end 178.000914 -215.166702)
		(width 0.381)
		(layer "F.Cu")
		(net "GND")
	)
	(segment
		(start 406.753314 -313.766708)
		(end 405.429212 -313.766708)
		(width 0.381)
		(layer "F.Cu")
		(net "GND")
	)
	(segment
		(start 106.471212 -232.250234)
		(end 106.471212 -231.714548)
		(width 0.254)
		(layer "F.Cu")
		(net "GND")
	)
	(segment
		(start 178.985164 -354.02901)
		(end 178.590956 -353.634802)
		(width 0.2032)
		(layer "F.Cu")
		(net "GND")
	)
	(segment
		(start 204.076046 -287.416748)
		(end 205.180946 -287.416748)
		(width 0.381)
		(layer "F.Cu")
		(net "GND")
	)
	(segment
		(start 40.506396 -335.471262)
		(end 41.446704 -335.471262)
		(width 0.508)
		(layer "F.Cu")
		(net "GND")
	)
	(segment
		(start 22.123146 -210.916774)
		(end 23.228046 -210.916774)
		(width 0.381)
		(layer "F.Cu")
		(net "GND")
	)
	(segment
		(start 423.804842 -384.266948)
		(end 423.14876 -384.266948)
		(width 0.3556)
		(layer "F.Cu")
		(net "GND")
	)
	(segment
		(start 158.813246 -221.96679)
		(end 157.708346 -221.96679)
		(width 0.381)
		(layer "F.Cu")
		(net "GND")
	)
	(segment
		(start 414.297114 -315.46673)
		(end 415.402014 -315.46673)
		(width 0.381)
		(layer "F.Cu")
		(net "GND")
	)
	(segment
		(start 49.666906 -8.320024)
		(end 49.666906 -7.215124)
		(width 0.3556)
		(layer "F.Cu")
		(net "GND")
	)
	(segment
		(start 162.913314 -198.166736)
		(end 164.018214 -198.166736)
		(width 0.381)
		(layer "F.Cu")
		(net "GND")
	)
	(segment
		(start 460.58709 -41.652444)
		(end 459.95209 -41.652444)
		(width 0.3556)
		(layer "F.Cu")
		(net "GND")
	)
	(segment
		(start 450.911214 -210.916774)
		(end 452.016114 -210.916774)
		(width 0.381)
		(layer "F.Cu")
		(net "GND")
	)
	(segment
		(start 341.364316 -257.45313)
		(end 341.364316 -257.988816)
		(width 0.2032)
		(layer "F.Cu")
		(net "GND")
	)
	(segment
		(start 261.285482 -207.51673)
		(end 260.180582 -207.51673)
		(width 0.381)
		(layer "F.Cu")
		(net "GND")
	)
	(segment
		(start 338.434934 -225.203512)
		(end 338.43468 -225.203258)
		(width 0.2032)
		(layer "F.Cu")
		(net "GND")
	)
	(segment
		(start 127.257048 -257.45313)
		(end 127.257048 -257.98907)
		(width 0.2032)
		(layer "F.Cu")
		(net "GND")
	)
	(segment
		(start 353.00158 -229.808786)
		(end 353.001834 -229.808532)
		(width 0.2032)
		(layer "F.Cu")
		(net "GND")
	)
	(segment
		(start 385.069842 -258.80314)
		(end 385.064762 -258.80314)
		(width 0.254)
		(layer "F.Cu")
		(net "GND")
	)
	(segment
		(start 414.756854 -8.320024)
		(end 414.756854 -7.215124)
		(width 0.3556)
		(layer "F.Cu")
		(net "GND")
	)
	(segment
		(start 95.193866 -235.506006)
		(end 95.193612 -235.505752)
		(width 0.2032)
		(layer "F.Cu")
		(net "GND")
	)
	(segment
		(start 58.533538 -207.51673)
		(end 57.503314 -207.51673)
		(width 0.381)
		(layer "F.Cu")
		(net "GND")
	)
	(segment
		(start 48.854614 -230.466646)
		(end 49.959514 -230.466646)
		(width 0.381)
		(layer "F.Cu")
		(net "GND")
	)
	(segment
		(start 195.427346 -199.01662)
		(end 196.532246 -199.01662)
		(width 0.381)
		(layer "F.Cu")
		(net "GND")
	)
	(segment
		(start 175.005746 -270.416782)
		(end 173.900846 -270.416782)
		(width 0.381)
		(layer "F.Cu")
		(net "GND")
	)
	(segment
		(start 11.135614 -245.76659)
		(end 12.240514 -245.76659)
		(width 0.381)
		(layer "F.Cu")
		(net "GND")
	)
	(segment
		(start 20.889214 -200.716642)
		(end 19.784314 -200.716642)
		(width 0.381)
		(layer "F.Cu")
		(net "GND")
	)
	(segment
		(start 420.991538 -182.290974)
		(end 421.618156 -182.290974)
		(width 0.381)
		(layer "F.Cu")
		(net "GND")
	)
	(segment
		(start 63.726314 -303.566576)
		(end 65.047114 -303.566576)
		(width 0.381)
		(layer "F.Cu")
		(net "GND")
	)
	(segment
		(start 136.184894 -279.428194)
		(end 136.184894 -279.964134)
		(width 0.2032)
		(layer "F.Cu")
		(net "GND")
	)
	(segment
		(start 190.093346 -201.56678)
		(end 188.988446 -201.56678)
		(width 0.381)
		(layer "F.Cu")
		(net "GND")
	)
	(segment
		(start 339.84438 -226.017582)
		(end 339.844634 -226.017328)
		(width 0.254)
		(layer "F.Cu")
		(net "GND")
	)
	(segment
		(start 92.844112 -247.178576)
		(end 92.844366 -247.178322)
		(width 0.2032)
		(layer "F.Cu")
		(net "GND")
	)
	(segment
		(start 178.9557 -114.575336)
		(end 179.35575 -114.975386)
		(width 0.3556)
		(layer "F.Cu")
		(net "GND")
	)
	(segment
		(start 185.544714 -226.216718)
		(end 184.439814 -226.216718)
		(width 0.381)
		(layer "F.Cu")
		(net "GND")
	)
	(segment
		(start 102.242112 -216.78646)
		(end 102.242112 -216.250774)
		(width 0.254)
		(layer "F.Cu")
		(net "GND")
	)
	(segment
		(start 122.917966 -246.086376)
		(end 122.917966 -245.55069)
		(width 0.2032)
		(layer "F.Cu")
		(net "GND")
	)
	(segment
		(start 347.184472 -37.424614)
		(end 346.973906 -37.63518)
		(width 0.254)
		(layer "F.Cu")
		(net "GND")
	)
	(segment
		(start 272.273014 -276.366732)
		(end 271.168114 -276.366732)
		(width 0.381)
		(layer "F.Cu")
		(net "GND")
	)
	(segment
		(start 345.407234 -42.72915)
		(end 345.554554 -42.94759)
		(width 0.2032)
		(layer "F.Cu")
		(net "GND")
	)
	(segment
		(start 33.767014 -215.166702)
		(end 34.871914 -215.166702)
		(width 0.381)
		(layer "F.Cu")
		(net "GND")
	)
	(segment
		(start 49.959514 -267.866622)
		(end 51.064414 -267.866622)
		(width 0.381)
		(layer "F.Cu")
		(net "GND")
	)
	(segment
		(start 346.063316 -270.475456)
		(end 346.063316 -271.011142)
		(width 0.2032)
		(layer "F.Cu")
		(net "GND")
	)
	(segment
		(start 355.82098 -229.808786)
		(end 355.821234 -229.808532)
		(width 0.2032)
		(layer "F.Cu")
		(net "GND")
	)
	(segment
		(start 96.243648 -272.103342)
		(end 96.243648 -272.639028)
		(width 0.2032)
		(layer "F.Cu")
		(net "GND")
	)
	(segment
		(start 37.977572 -132.79374)
		(end 37.356288 -132.79374)
		(width 0.381)
		(layer "F.Cu")
		(net "GND")
	)
	(segment
		(start 449.677282 -226.216718)
		(end 448.572382 -226.216718)
		(width 0.381)
		(layer "F.Cu")
		(net "GND")
	)
	(segment
		(start 271.168114 -195.616576)
		(end 270.063214 -195.616576)
		(width 0.381)
		(layer "F.Cu")
		(net "GND")
	)
	(segment
		(start 328.53122 -21.354288)
		(end 328.801984 -21.625052)
		(width 0.3556)
		(layer "F.Cu")
		(net "GND")
	)
	(segment
		(start 342.304116 -281.869896)
		(end 342.304116 -282.405836)
		(width 0.254)
		(layer "F.Cu")
		(net "GND")
	)
	(segment
		(start 370.498116 -260.708902)
		(end 370.498116 -261.244588)
		(width 0.2032)
		(layer "F.Cu")
		(net "GND")
	)
	(segment
		(start 341.72398 -223.297496)
		(end 341.72398 -222.76181)
		(width 0.254)
		(layer "F.Cu")
		(net "GND")
	)
	(segment
		(start 344.63355 -54.089046)
		(end 345.15171 -54.354476)
		(width 0.2032)
		(layer "F.Cu")
		(net "GND")
	)
	(segment
		(start 188.988446 -208.366614)
		(end 187.883546 -208.366614)
		(width 0.381)
		(layer "F.Cu")
		(net "GND")
	)
	(segment
		(start 383.545334 -237.133892)
		(end 383.54508 -237.133638)
		(width 0.254)
		(layer "F.Cu")
		(net "GND")
	)
	(segment
		(start 333.26578 -217.974672)
		(end 333.315564 -217.924888)
		(width 0.2032)
		(layer "F.Cu")
		(net "GND")
	)
	(segment
		(start 362.509562 -276.172676)
		(end 362.509562 -276.708362)
		(width 0.254)
		(layer "F.Cu")
		(net "GND")
	)
	(segment
		(start 336.665316 -267.219938)
		(end 336.665316 -267.755624)
		(width 0.2032)
		(layer "F.Cu")
		(net "GND")
	)
	(segment
		(start 378.37618 -223.297496)
		(end 378.37618 -222.76181)
		(width 0.254)
		(layer "F.Cu")
		(net "GND")
	)
	(segment
		(start 312.987182 -226.216718)
		(end 311.882282 -226.216718)
		(width 0.381)
		(layer "F.Cu")
		(net "GND")
	)
	(segment
		(start 48.854614 -224.516696)
		(end 49.959514 -224.516696)
		(width 0.381)
		(layer "F.Cu")
		(net "GND")
	)
	(segment
		(start 260.180582 -219.41663)
		(end 259.075682 -219.41663)
		(width 0.381)
		(layer "F.Cu")
		(net "GND")
	)
	(segment
		(start 342.66378 -241.203226)
		(end 342.664034 -241.202972)
		(width 0.2032)
		(layer "F.Cu")
		(net "GND")
	)
	(segment
		(start 271.168114 -265.316716)
		(end 270.063214 -265.316716)
		(width 0.381)
		(layer "F.Cu")
		(net "GND")
	)
	(segment
		(start 84.856066 -233.87812)
		(end 84.386166 -234.15625)
		(width 0.2032)
		(layer "F.Cu")
		(net "GND")
	)
	(segment
		(start 293.799514 -260.21665)
		(end 292.694614 -260.21665)
		(width 0.381)
		(layer "F.Cu")
		(net "GND")
	)
	(segment
		(start 338.90458 -236.319822)
		(end 338.90458 -235.783882)
		(width 0.2032)
		(layer "F.Cu")
		(net "GND")
	)
	(segment
		(start 368.148362 -281.05608)
		(end 368.148616 -281.59202)
		(width 0.254)
		(layer "F.Cu")
		(net "GND")
	)
	(segment
		(start 105.061766 -220.041724)
		(end 105.061766 -219.506038)
		(width 0.254)
		(layer "F.Cu")
		(net "GND")
	)
	(segment
		(start 256.080514 -214.316564)
		(end 257.185414 -214.316564)
		(width 0.381)
		(layer "F.Cu")
		(net "GND")
	)
	(segment
		(start 340.894162 -286.47517)
		(end 340.894416 -286.475424)
		(width 0.2032)
		(layer "F.Cu")
		(net "GND")
	)
	(segment
		(start 65.047114 -295.916604)
		(end 66.152014 -295.916604)
		(width 0.381)
		(layer "F.Cu")
		(net "GND")
	)
	(segment
		(start 97.653094 -279.428194)
		(end 97.653094 -279.96388)
		(width 0.254)
		(layer "F.Cu")
		(net "GND")
	)
	(segment
		(start 207.071214 -228.766624)
		(end 208.176114 -228.766624)
		(width 0.381)
		(layer "F.Cu")
		(net "GND")
	)
	(segment
		(start 92.954094 -279.428194)
		(end 92.954094 -279.96388)
		(width 0.254)
		(layer "F.Cu")
		(net "GND")
	)
	(segment
		(start 52.298346 -216.016586)
		(end 53.403246 -216.016586)
		(width 0.381)
		(layer "F.Cu")
		(net "GND")
	)
	(segment
		(start 171.562014 -230.466646)
		(end 170.457114 -230.466646)
		(width 0.381)
		(layer "F.Cu")
		(net "GND")
	)
	(segment
		(start 372.847616 -281.591766)
		(end 372.847616 -281.59202)
		(width 0.254)
		(layer "F.Cu")
		(net "GND")
	)
	(segment
		(start 336.085434 -221.669864)
		(end 336.085434 -221.133924)
		(width 0.254)
		(layer "F.Cu")
		(net "GND")
	)
	(segment
		(start 123.027694 -279.96388)
		(end 123.027948 -279.964134)
		(width 0.254)
		(layer "F.Cu")
		(net "GND")
	)
	(segment
		(start 97.543112 -222.76181)
		(end 97.543366 -222.761556)
		(width 0.254)
		(layer "F.Cu")
		(net "GND")
	)
	(segment
		(start 121.508012 -239.853216)
		(end 121.508012 -240.388902)
		(width 0.2032)
		(layer "F.Cu")
		(net "GND")
	)
	(segment
		(start 27.328114 -211.766658)
		(end 28.433014 -211.766658)
		(width 0.381)
		(layer "F.Cu")
		(net "GND")
	)
	(segment
		(start 99.063048 -284.033468)
		(end 99.062794 -284.033722)
		(width 0.254)
		(layer "F.Cu")
		(net "GND")
	)
	(segment
		(start 178.000914 -299.316648)
		(end 179.105814 -299.316648)
		(width 0.381)
		(layer "F.Cu")
		(net "GND")
	)
	(segment
		(start 459.559914 -265.316716)
		(end 458.455014 -265.316716)
		(width 0.381)
		(layer "F.Cu")
		(net "GND")
	)
	(segment
		(start 162.913314 -221.116652)
		(end 161.808414 -221.116652)
		(width 0.381)
		(layer "F.Cu")
		(net "GND")
	)
	(segment
		(start 286.255714 -231.316784)
		(end 287.360614 -231.316784)
		(width 0.381)
		(layer "F.Cu")
		(net "GND")
	)
	(segment
		(start 436.928514 -201.56678)
		(end 438.033414 -201.56678)
		(width 0.381)
		(layer "F.Cu")
		(net "GND")
	)
	(segment
		(start 276.373082 -308.666642)
		(end 275.268182 -308.666642)
		(width 0.381)
		(layer "F.Cu")
		(net "GND")
	)
	(segment
		(start 134.305294 -253.383796)
		(end 134.305294 -253.919482)
		(width 0.2032)
		(layer "F.Cu")
		(net "GND")
	)
	(segment
		(start 308.887114 -227.066602)
		(end 309.992014 -227.066602)
		(width 0.381)
		(layer "F.Cu")
		(net "GND")
	)
	(segment
		(start 441.028582 -266.1666)
		(end 442.133482 -266.1666)
		(width 0.381)
		(layer "F.Cu")
		(net "GND")
	)
	(segment
		(start 267.724382 -271.266666)
		(end 268.829282 -271.266666)
		(width 0.381)
		(layer "F.Cu")
		(net "GND")
	)
	(segment
		(start 369.088162 -281.591512)
		(end 369.088416 -281.591766)
		(width 0.254)
		(layer "F.Cu")
		(net "GND")
	)
	(segment
		(start 337.49488 -233.877866)
		(end 337.49488 -233.34218)
		(width 0.2032)
		(layer "F.Cu")
		(net "GND")
	)
	(segment
		(start 340.784434 -249.341894)
		(end 340.784434 -248.806208)
		(width 0.2032)
		(layer "F.Cu")
		(net "GND")
	)
	(segment
		(start 118.781576 -338.70265)
		(end 118.781576 -339.339174)
		(width 0.381)
		(layer "F.Cu")
		(net "GND")
	)
	(segment
		(start 116.339366 -229.808532)
		(end 116.339366 -229.272846)
		(width 0.254)
		(layer "F.Cu")
		(net "GND")
	)
	(segment
		(start 439.923682 -224.516696)
		(end 441.028582 -224.516696)
		(width 0.381)
		(layer "F.Cu")
		(net "GND")
	)
	(segment
		(start 104.231694 -285.939484)
		(end 104.231694 -286.475424)
		(width 0.254)
		(layer "F.Cu")
		(net "GND")
	)
	(segment
		(start 100.362512 -223.297496)
		(end 100.362512 -222.76181)
		(width 0.254)
		(layer "F.Cu")
		(net "GND")
	)
	(segment
		(start 414.297114 -309.51678)
		(end 415.402014 -309.51678)
		(width 0.381)
		(layer "F.Cu")
		(net "GND")
	)
	(segment
		(start 126.317248 -278.614378)
		(end 126.317248 -279.150064)
		(width 0.254)
		(layer "F.Cu")
		(net "GND")
	)
	(segment
		(start 297.899582 -202.416664)
		(end 299.004482 -202.416664)
		(width 0.381)
		(layer "F.Cu")
		(net "GND")
	)
	(segment
		(start 133.027674 -366.445546)
		(end 133.725412 -365.747808)
		(width 0.508)
		(layer "F.Cu")
		(net "GND")
	)
	(segment
		(start 181.444646 -287.416748)
		(end 180.339746 -287.416748)
		(width 0.381)
		(layer "F.Cu")
		(net "GND")
	)
	(segment
		(start 460.664814 -263.616694)
		(end 459.559914 -263.616694)
		(width 0.381)
		(layer "F.Cu")
		(net "GND")
	)
	(segment
		(start 125.377448 -280.242264)
		(end 125.377194 -280.778204)
		(width 0.2032)
		(layer "F.Cu")
		(net "GND")
	)
	(segment
		(start 192.62344 -70.134988)
		(end 192.834768 -69.92366)
		(width 0.254)
		(layer "F.Cu")
		(net "GND")
	)
	(segment
		(start 202.971146 -290.816792)
		(end 204.076046 -290.816792)
		(width 0.381)
		(layer "F.Cu")
		(net "GND")
	)
	(segment
		(start 281.707082 -247.466612)
		(end 282.811982 -247.466612)
		(width 0.381)
		(layer "F.Cu")
		(net "GND")
	)
	(segment
		(start 119.738648 -284.033468)
		(end 119.738394 -284.033722)
		(width 0.254)
		(layer "F.Cu")
		(net "GND")
	)
	(segment
		(start 344.903552 -59.265312)
		(end 345.403932 -58.850276)
		(width 0.2032)
		(layer "F.Cu")
		(net "GND")
	)
	(segment
		(start 305.443382 -241.516662)
		(end 306.548282 -241.516662)
		(width 0.381)
		(layer "F.Cu")
		(net "GND")
	)
	(segment
		(start 378.846334 -232.250488)
		(end 378.84608 -232.250234)
		(width 0.2032)
		(layer "F.Cu")
		(net "GND")
	)
	(segment
		(start 179.755546 -120.975374)
		(end 180.155596 -121.375424)
		(width 0.3556)
		(layer "F.Cu")
		(net "GND")
	)
	(segment
		(start 113.050066 -215.972644)
		(end 113.050066 -215.436958)
		(width 0.2032)
		(layer "F.Cu")
		(net "GND")
	)
	(segment
		(start 300.238414 -278.066754)
		(end 301.343314 -278.066754)
		(width 0.381)
		(layer "F.Cu")
		(net "GND")
	)
	(segment
		(start 394.899896 -57.030112)
		(end 394.899642 -57.030366)
		(width 0.3556)
		(layer "F.Cu")
		(net "GND")
	)
	(segment
		(start 338.544916 -267.219938)
		(end 338.544916 -267.755878)
		(width 0.2032)
		(layer "F.Cu")
		(net "GND")
	)
	(segment
		(start 421.840914 -223.666558)
		(end 422.945814 -223.666558)
		(width 0.381)
		(layer "F.Cu")
		(net "GND")
	)
	(segment
		(start 282.811982 -241.516662)
		(end 283.916882 -241.516662)
		(width 0.381)
		(layer "F.Cu")
		(net "GND")
	)
	(segment
		(start 286.255714 -309.51678)
		(end 287.360614 -309.51678)
		(width 0.381)
		(layer "F.Cu")
		(net "GND")
	)
	(segment
		(start 312.987182 -261.066788)
		(end 314.092082 -261.066788)
		(width 0.381)
		(layer "F.Cu")
		(net "GND")
	)
	(segment
		(start 439.923682 -244.066568)
		(end 441.028582 -244.066568)
		(width 0.381)
		(layer "F.Cu")
		(net "GND")
	)
	(segment
		(start 181.7624 -94.738698)
		(end 181.7624 -95.367348)
		(width 0.3556)
		(layer "F.Cu")
		(net "GND")
	)
	(segment
		(start 458.867764 -381.606806)
		(end 458.109828 -380.84887)
		(width 0.3556)
		(layer "F.Cu")
		(net "GND")
	)
	(segment
		(start 340.78418 -244.458744)
		(end 340.784434 -244.45849)
		(width 0.2032)
		(layer "F.Cu")
		(net "GND")
	)
	(segment
		(start 441.028582 -249.166634)
		(end 442.133482 -249.166634)
		(width 0.381)
		(layer "F.Cu")
		(net "GND")
	)
	(segment
		(start 15.684246 -236.416596)
		(end 16.789146 -236.416596)
		(width 0.381)
		(layer "F.Cu")
		(net "GND")
	)
	(segment
		(start 15.684246 -250.016772)
		(end 16.789146 -250.016772)
		(width 0.381)
		(layer "F.Cu")
		(net "GND")
	)
	(segment
		(start 110.340648 -273.730974)
		(end 110.340648 -274.26666)
		(width 0.254)
		(layer "F.Cu")
		(net "GND")
	)
	(segment
		(start 44.754546 -251.716794)
		(end 45.859446 -251.716794)
		(width 0.381)
		(layer "F.Cu")
		(net "GND")
	)
	(segment
		(start 44.754546 -203.266802)
		(end 45.859446 -203.266802)
		(width 0.381)
		(layer "F.Cu")
		(net "GND")
	)
	(segment
		(start 122.447812 -233.877866)
		(end 122.447812 -233.34218)
		(width 0.254)
		(layer "F.Cu")
		(net "GND")
	)
	(segment
		(start 89.555066 -243.644928)
		(end 89.554812 -243.644674)
		(width 0.2032)
		(layer "F.Cu")
		(net "GND")
	)
	(segment
		(start 19.784314 -286.56661)
		(end 20.889214 -286.56661)
		(width 0.381)
		(layer "F.Cu")
		(net "GND")
	)
	(segment
		(start 301.343314 -311.216802)
		(end 302.664114 -311.216802)
		(width 0.381)
		(layer "F.Cu")
		(net "GND")
	)
	(segment
		(start 337.495134 -240.389156)
		(end 337.49488 -240.388902)
		(width 0.2032)
		(layer "F.Cu")
		(net "GND")
	)
	(segment
		(start 101.882448 -276.986492)
		(end 101.882448 -277.522432)
		(width 0.254)
		(layer "F.Cu")
		(net "GND")
	)
	(segment
		(start 429.384714 -292.516814)
		(end 430.489614 -292.516814)
		(width 0.381)
		(layer "F.Cu")
		(net "GND")
	)
	(segment
		(start 373.677434 -249.341894)
		(end 373.677434 -248.806208)
		(width 0.2032)
		(layer "F.Cu")
		(net "GND")
	)
	(segment
		(start 35.976814 -295.916604)
		(end 34.871914 -295.916604)
		(width 0.381)
		(layer "F.Cu")
		(net "GND")
	)
	(segment
		(start 131.956048 -272.103342)
		(end 131.956048 -272.639282)
		(width 0.2032)
		(layer "F.Cu")
		(net "GND")
	)
	(segment
		(start 107.990894 -279.428194)
		(end 107.990894 -279.964134)
		(width 0.254)
		(layer "F.Cu")
		(net "GND")
	)
	(segment
		(start 53.403246 -233.016806)
		(end 54.508146 -233.016806)
		(width 0.381)
		(layer "F.Cu")
		(net "GND")
	)
	(segment
		(start 108.31576 -408.036014)
		(end 108.951014 -408.036014)
		(width 0.3556)
		(layer "F.Cu")
		(net "GND")
	)
	(segment
		(start 181.444646 -307.816758)
		(end 180.339746 -307.816758)
		(width 0.381)
		(layer "F.Cu")
		(net "GND")
	)
	(segment
		(start 260.180582 -213.46668)
		(end 259.075682 -213.46668)
		(width 0.381)
		(layer "F.Cu")
		(net "GND")
	)
	(segment
		(start 335.615534 -228.99497)
		(end 335.615534 -228.45903)
		(width 0.254)
		(layer "F.Cu")
		(net "GND")
	)
	(segment
		(start 136.184894 -288.102802)
		(end 136.185148 -288.103056)
		(width 0.254)
		(layer "F.Cu")
		(net "GND")
	)
	(segment
		(start 348.412562 -289.195002)
		(end 348.412562 -289.807142)
		(width 0.2032)
		(layer "F.Cu")
		(net "GND")
	)
	(segment
		(start 328.194162 -52.36718)
		(end 328.168 -52.303934)
		(width 0.2032)
		(layer "F.Cu")
		(net "GND")
	)
	(segment
		(start 112.110266 -217.600276)
		(end 112.110266 -217.064336)
		(width 0.2032)
		(layer "F.Cu")
		(net "GND")
	)
	(segment
		(start 169.144442 -238.116618)
		(end 170.457114 -238.116618)
		(width 0.381)
		(layer "F.Cu")
		(net "GND")
	)
	(segment
		(start 347.003116 -284.033468)
		(end 347.002862 -284.033722)
		(width 0.254)
		(layer "F.Cu")
		(net "GND")
	)
	(segment
		(start 59.842146 -236.416596)
		(end 60.947046 -236.416596)
		(width 0.381)
		(layer "F.Cu")
		(net "GND")
	)
	(segment
		(start 431.47488 -128.761998)
		(end 430.81448 -128.761998)
		(width 0.3556)
		(layer "F.Cu")
		(net "GND")
	)
	(segment
		(start 335.14538 -228.1809)
		(end 335.14538 -227.64496)
		(width 0.254)
		(layer "F.Cu")
		(net "GND")
	)
	(segment
		(start 336.085434 -216.250774)
		(end 336.08518 -216.25052)
		(width 0.2032)
		(layer "F.Cu")
		(net "GND")
	)
	(segment
		(start 453.121014 -231.316784)
		(end 452.016114 -231.316784)
		(width 0.381)
		(layer "F.Cu")
		(net "GND")
	)
	(segment
		(start 122.917712 -226.553268)
		(end 122.917712 -226.017582)
		(width 0.254)
		(layer "F.Cu")
		(net "GND")
	)
	(segment
		(start 193.088514 -316.316614)
		(end 194.193414 -316.316614)
		(width 0.381)
		(layer "F.Cu")
		(net "GND")
	)
	(segment
		(start 91.544394 -283.498036)
		(end 91.544394 -284.033722)
		(width 0.254)
		(layer "F.Cu")
		(net "GND")
	)
	(segment
		(start 90.494866 -230.622602)
		(end 90.494866 -230.086916)
		(width 0.254)
		(layer "F.Cu")
		(net "GND")
	)
	(segment
		(start 386.364734 -225.739198)
		(end 386.364734 -225.203258)
		(width 0.254)
		(layer "F.Cu")
		(net "GND")
	)
	(segment
		(start 9.245346 -251.716794)
		(end 8.140446 -251.716794)
		(width 0.381)
		(layer "F.Cu")
		(net "GND")
	)
	(segment
		(start 114.099848 -266.127992)
		(end 114.099594 -266.128246)
		(width 0.254)
		(layer "F.Cu")
		(net "GND")
	)
	(segment
		(start 344.183716 -254.197612)
		(end 344.183716 -254.733044)
		(width 0.2032)
		(layer "F.Cu")
		(net "GND")
	)
	(segment
		(start 163.10483 -438.495948)
		(end 162.49523 -438.495948)
		(width 0.3556)
		(layer "F.Cu")
		(net "GND")
	)
	(segment
		(start 45.859446 -285.716726)
		(end 46.964346 -285.716726)
		(width 0.381)
		(layer "F.Cu")
		(net "GND")
	)
	(segment
		(start 337.604862 -263.96442)
		(end 337.604862 -264.50036)
		(width 0.2032)
		(layer "F.Cu")
		(net "GND")
	)
	(segment
		(start 370.498116 -254.197612)
		(end 370.498116 -254.733298)
		(width 0.254)
		(layer "F.Cu")
		(net "GND")
	)
	(segment
		(start 65.047114 -221.116652)
		(end 66.152014 -221.116652)
		(width 0.381)
		(layer "F.Cu")
		(net "GND")
	)
	(segment
		(start 382.135634 -239.57534)
		(end 382.135634 -239.0394)
		(width 0.2032)
		(layer "F.Cu")
		(net "GND")
	)
	(segment
		(start 354.411534 -220.855794)
		(end 354.411534 -220.319854)
		(width 0.2032)
		(layer "F.Cu")
		(net "GND")
	)
	(segment
		(start 244.75694 -251.198888)
		(end 244.75694 -249.248168)
		(width 0.3556)
		(layer "F.Cu")
		(net "GND")
	)
	(segment
		(start 200.632314 -294.216582)
		(end 201.737214 -294.216582)
		(width 0.381)
		(layer "F.Cu")
		(net "GND")
	)
	(segment
		(start 26.223214 -219.41663)
		(end 27.328114 -219.41663)
		(width 0.381)
		(layer "F.Cu")
		(net "GND")
	)
	(segment
		(start 272.273014 -238.966756)
		(end 271.168114 -238.966756)
		(width 0.381)
		(layer "F.Cu")
		(net "GND")
	)
	(segment
		(start 270.063214 -227.066602)
		(end 271.168114 -227.066602)
		(width 0.381)
		(layer "F.Cu")
		(net "GND")
	)
	(segment
		(start 358.280716 -276.986492)
		(end 358.280716 -277.522178)
		(width 0.254)
		(layer "F.Cu")
		(net "GND")
	)
	(segment
		(start 407.858214 -315.46673)
		(end 406.753314 -315.46673)
		(width 0.381)
		(layer "F.Cu")
		(net "GND")
	)
	(segment
		(start 364.82782 -386.372608)
		(end 365.380524 -385.819904)
		(width 0.3556)
		(layer "F.Cu")
		(net "GND")
	)
	(segment
		(start 129.136648 -266.127992)
		(end 129.136394 -266.128246)
		(width 0.254)
		(layer "F.Cu")
		(net "GND")
	)
	(segment
		(start 437.70296 -47.0408)
		(end 438.216548 -47.0408)
		(width 0.3556)
		(layer "F.Cu")
		(net "GND")
	)
	(segment
		(start 262.519414 -283.166566)
		(end 263.624314 -283.166566)
		(width 0.381)
		(layer "F.Cu")
		(net "GND")
	)
	(segment
		(start 161.808414 -258.516628)
		(end 162.913314 -258.516628)
		(width 0.381)
		(layer "F.Cu")
		(net "GND")
	)
	(segment
		(start 375.557034 -247.714008)
		(end 375.557034 -247.178322)
		(width 0.2032)
		(layer "F.Cu")
		(net "GND")
	)
	(segment
		(start 88.255094 -258.2672)
		(end 88.255094 -258.80314)
		(width 0.2032)
		(layer "F.Cu")
		(net "GND")
	)
	(segment
		(start 166.357046 -273.816572)
		(end 167.665146 -273.816572)
		(width 0.381)
		(layer "F.Cu")
		(net "GND")
	)
	(segment
		(start 15.684246 -260.21665)
		(end 16.789146 -260.21665)
		(width 0.381)
		(layer "F.Cu")
		(net "GND")
	)
	(segment
		(start 199.527414 -211.766658)
		(end 200.632314 -211.766658)
		(width 0.381)
		(layer "F.Cu")
		(net "GND")
	)
	(segment
		(start 52.298346 -278.066754)
		(end 53.403246 -278.066754)
		(width 0.381)
		(layer "F.Cu")
		(net "GND")
	)
	(segment
		(start 364.389162 -286.47517)
		(end 364.389416 -286.475424)
		(width 0.254)
		(layer "F.Cu")
		(net "GND")
	)
	(segment
		(start 57.503314 -277.216616)
		(end 58.608214 -277.216616)
		(width 0.381)
		(layer "F.Cu")
		(net "GND")
	)
	(segment
		(start 103.931212 -60.128404)
		(end 102.991412 -60.128404)
		(width 0.3556)
		(layer "F.Cu")
		(net "GND")
	)
	(segment
		(start 452.016114 -260.21665)
		(end 450.911214 -260.21665)
		(width 0.381)
		(layer "F.Cu")
		(net "GND")
	)
	(segment
		(start 296.794682 -269.566644)
		(end 297.899582 -269.566644)
		(width 0.381)
		(layer "F.Cu")
		(net "GND")
	)
	(segment
		(start 272.273014 -313.766708)
		(end 271.168114 -313.766708)
		(width 0.381)
		(layer "F.Cu")
		(net "GND")
	)
	(segment
		(start 164.24783 -122.646948)
		(end 163.63823 -122.646948)
		(width 0.3556)
		(layer "F.Cu")
		(net "GND")
	)
	(segment
		(start 98.013266 -237.133892)
		(end 98.013012 -237.133638)
		(width 0.2032)
		(layer "F.Cu")
		(net "GND")
	)
	(segment
		(start 372.73738 -216.78646)
		(end 372.73738 -216.250774)
		(width 0.254)
		(layer "F.Cu")
		(net "GND")
	)
	(segment
		(start 286.255714 -267.016738)
		(end 287.360614 -267.016738)
		(width 0.381)
		(layer "F.Cu")
		(net "GND")
	)
	(segment
		(start 23.228046 -278.066754)
		(end 24.332946 -278.066754)
		(width 0.381)
		(layer "F.Cu")
		(net "GND")
	)
	(segment
		(start 331.666596 -277.410672)
		(end 332.904592 -276.172676)
		(width 0.2032)
		(layer "F.Cu")
		(net "GND")
	)
	(segment
		(start 359.58018 -217.87866)
		(end 359.580434 -217.878406)
		(width 0.2032)
		(layer "F.Cu")
		(net "GND")
	)
	(segment
		(start 305.443382 -250.866656)
		(end 306.548282 -250.866656)
		(width 0.381)
		(layer "F.Cu")
		(net "GND")
	)
	(segment
		(start 124.907294 -255.011682)
		(end 124.907294 -255.547622)
		(width 0.2032)
		(layer "F.Cu")
		(net "GND")
	)
	(segment
		(start 11.135614 -205.816708)
		(end 12.240514 -205.816708)
		(width 0.381)
		(layer "F.Cu")
		(net "GND")
	)
	(segment
		(start 23.646892 -415.127948)
		(end 23.037292 -415.127948)
		(width 0.3556)
		(layer "F.Cu")
		(net "GND")
	)
	(segment
		(start 406.753314 -250.016772)
		(end 407.858214 -250.016772)
		(width 0.381)
		(layer "F.Cu")
		(net "GND")
	)
	(segment
		(start 199.527414 -299.316648)
		(end 200.632314 -299.316648)
		(width 0.381)
		(layer "F.Cu")
		(net "GND")
	)
	(segment
		(start 271.168114 -220.266768)
		(end 270.063214 -220.266768)
		(width 0.381)
		(layer "F.Cu")
		(net "GND")
	)
	(segment
		(start 285.150814 -298.466764)
		(end 286.255714 -298.466764)
		(width 0.381)
		(layer "F.Cu")
		(net "GND")
	)
	(segment
		(start 26.223214 -204.116686)
		(end 27.328114 -204.116686)
		(width 0.381)
		(layer "F.Cu")
		(net "GND")
	)
	(segment
		(start 338.544916 -286.7533)
		(end 338.544916 -287.28924)
		(width 0.254)
		(layer "F.Cu")
		(net "GND")
	)
	(segment
		(start 92.954094 -253.919482)
		(end 92.954348 -253.919736)
		(width 0.2032)
		(layer "F.Cu")
		(net "GND")
	)
	(segment
		(start 312.987182 -221.116652)
		(end 314.092082 -221.116652)
		(width 0.381)
		(layer "F.Cu")
		(net "GND")
	)
	(segment
		(start 380.835916 -260.708902)
		(end 380.835916 -261.244588)
		(width 0.2032)
		(layer "F.Cu")
		(net "GND")
	)
	(segment
		(start 305.443382 -291.666676)
		(end 306.764182 -291.666676)
		(width 0.381)
		(layer "F.Cu")
		(net "GND")
	)
	(segment
		(start 171.755562 -105.775506)
		(end 171.355512 -105.375456)
		(width 0.3556)
		(layer "F.Cu")
		(net "GND")
	)
	(segment
		(start 429.384714 -206.666592)
		(end 430.489614 -206.666592)
		(width 0.381)
		(layer "F.Cu")
		(net "GND")
	)
	(segment
		(start 344.07348 -246.900192)
		(end 344.07348 -246.364506)
		(width 0.2032)
		(layer "F.Cu")
		(net "GND")
	)
	(segment
		(start 151.5872 -128.297178)
		(end 150.89886 -128.297178)
		(width 0.3556)
		(layer "F.Cu")
		(net "GND")
	)
	(segment
		(start 304.338482 -205.816708)
		(end 305.443382 -205.816708)
		(width 0.381)
		(layer "F.Cu")
		(net "GND")
	)
	(segment
		(start 432.379882 -250.866656)
		(end 433.484782 -250.866656)
		(width 0.381)
		(layer "F.Cu")
		(net "GND")
	)
	(segment
		(start 103.762048 -284.033468)
		(end 103.761794 -284.033722)
		(width 0.254)
		(layer "F.Cu")
		(net "GND")
	)
	(segment
		(start 369.000278 -425.882308)
		(end 369.000278 -424.535346)
		(width 0.3556)
		(layer "F.Cu")
		(net "GND")
	)
	(segment
		(start 281.707082 -213.46668)
		(end 282.811982 -213.46668)
		(width 0.381)
		(layer "F.Cu")
		(net "GND")
	)
	(segment
		(start 161.808414 -266.1666)
		(end 162.913314 -266.1666)
		(width 0.381)
		(layer "F.Cu")
		(net "GND")
	)
	(segment
		(start 65.047114 -294.216582)
		(end 66.152014 -294.216582)
		(width 0.381)
		(layer "F.Cu")
		(net "GND")
	)
	(segment
		(start 359.110788 -219.227908)
		(end 359.110788 -218.692222)
		(width 0.254)
		(layer "F.Cu")
		(net "GND")
	)
	(segment
		(start 45.859446 -236.416596)
		(end 46.964346 -236.416596)
		(width 0.381)
		(layer "F.Cu")
		(net "GND")
	)
	(segment
		(start 436.928514 -216.016586)
		(end 438.033414 -216.016586)
		(width 0.381)
		(layer "F.Cu")
		(net "GND")
	)
	(segment
		(start 345.953334 -237.133892)
		(end 345.95308 -237.133638)
		(width 0.2032)
		(layer "F.Cu")
		(net "GND")
	)
	(segment
		(start 164.220906 -312.91657)
		(end 162.913314 -312.91657)
		(width 0.381)
		(layer "F.Cu")
		(net "GND")
	)
	(segment
		(start 456.621388 -380.527306)
		(end 456.621388 -380.864872)
		(width 0.381)
		(layer "F.Cu")
		(net "GND")
	)
	(segment
		(start 339.954362 -255.011682)
		(end 339.954362 -255.547622)
		(width 0.2032)
		(layer "F.Cu")
		(net "GND")
	)
	(segment
		(start 137.82548 -26.251408)
		(end 137.00633 -26.251408)
		(width 0.3556)
		(layer "F.Cu")
		(net "GND")
	)
	(segment
		(start 134.305294 -269.66164)
		(end 134.305548 -270.167862)
		(width 0.2032)
		(layer "F.Cu")
		(net "GND")
	)
	(segment
		(start 342.73363 -47.980092)
		(end 343.00541 -48.449992)
		(width 0.254)
		(layer "F.Cu")
		(net "GND")
	)
	(segment
		(start 374.147334 -232.250488)
		(end 374.14708 -232.250234)
		(width 0.2032)
		(layer "F.Cu")
		(net "GND")
	)
	(segment
		(start 164.033454 -215.166702)
		(end 162.913314 -215.166702)
		(width 0.381)
		(layer "F.Cu")
		(net "GND")
	)
	(segment
		(start 128.748536 -342.270334)
		(end 129.383028 -342.270334)
		(width 0.3556)
		(layer "F.Cu")
		(net "GND")
	)
	(segment
		(start 168.066974 -13.600176)
		(end 168.066974 -12.495022)
		(width 0.3556)
		(layer "F.Cu")
		(net "GND")
	)
	(segment
		(start 262.519414 -244.916706)
		(end 263.624314 -244.916706)
		(width 0.381)
		(layer "F.Cu")
		(net "GND")
	)
	(segment
		(start 418.397182 -207.51673)
		(end 417.05403 -207.51673)
		(width 0.381)
		(layer "F.Cu")
		(net "GND")
	)
	(segment
		(start 344.543634 -220.041724)
		(end 344.543634 -219.506038)
		(width 0.254)
		(layer "F.Cu")
		(net "GND")
	)
	(segment
		(start 181.444646 -242.3668)
		(end 182.549546 -242.3668)
		(width 0.381)
		(layer "F.Cu")
		(net "GND")
	)
	(segment
		(start 202.971146 -283.166566)
		(end 204.076046 -283.166566)
		(width 0.381)
		(layer "F.Cu")
		(net "GND")
	)
	(segment
		(start 92.014294 -259.894832)
		(end 92.014294 -260.430772)
		(width 0.2032)
		(layer "F.Cu")
		(net "GND")
	)
	(segment
		(start 57.503314 -196.466714)
		(end 58.608214 -196.466714)
		(width 0.381)
		(layer "F.Cu")
		(net "GND")
	)
	(segment
		(start 125.847094 -282.683966)
		(end 125.847348 -282.68422)
		(width 0.254)
		(layer "F.Cu")
		(net "GND")
	)
	(segment
		(start 23.228046 -267.016738)
		(end 24.332946 -267.016738)
		(width 0.381)
		(layer "F.Cu")
		(net "GND")
	)
	(segment
		(start 100.832666 -237.133892)
		(end 100.832666 -236.597952)
		(width 0.2032)
		(layer "F.Cu")
		(net "GND")
	)
	(segment
		(start 427.045882 -314.616592)
		(end 425.940982 -314.616592)
		(width 0.381)
		(layer "F.Cu")
		(net "GND")
	)
	(segment
		(start 345.953334 -243.644928)
		(end 345.953334 -243.108988)
		(width 0.2032)
		(layer "F.Cu")
		(net "GND")
	)
	(segment
		(start 267.724382 -303.566576)
		(end 268.829282 -303.566576)
		(width 0.381)
		(layer "F.Cu")
		(net "GND")
	)
	(segment
		(start 267.724382 -194.766692)
		(end 268.829282 -194.766692)
		(width 0.381)
		(layer "F.Cu")
		(net "GND")
	)
	(segment
		(start 424.166792 -8.320024)
		(end 424.166792 -7.215124)
		(width 0.3556)
		(layer "F.Cu")
		(net "GND")
	)
	(segment
		(start 432.379882 -297.616626)
		(end 433.484782 -297.616626)
		(width 0.381)
		(layer "F.Cu")
		(net "GND")
	)
	(segment
		(start 349.242634 -231.436164)
		(end 349.242634 -230.900478)
		(width 0.2032)
		(layer "F.Cu")
		(net "GND")
	)
	(segment
		(start 42.415714 -301.01667)
		(end 41.310814 -301.01667)
		(width 0.381)
		(layer "F.Cu")
		(net "GND")
	)
	(segment
		(start 35.976814 -269.566644)
		(end 34.871914 -269.566644)
		(width 0.381)
		(layer "F.Cu")
		(net "GND")
	)
	(segment
		(start 98.67392 -82.235294)
		(end 97.97288 -82.235294)
		(width 0.3556)
		(layer "F.Cu")
		(net "GND")
	)
	(segment
		(start 382.245616 -270.167862)
		(end 382.245616 -270.19758)
		(width 0.2032)
		(layer "F.Cu")
		(net "GND")
	)
	(segment
		(start 92.844366 -241.202972)
		(end 92.844366 -240.667286)
		(width 0.2032)
		(layer "F.Cu")
		(net "GND")
	)
	(segment
		(start 19.784314 -198.166736)
		(end 18.679414 -198.166736)
		(width 0.381)
		(layer "F.Cu")
		(net "GND")
	)
	(segment
		(start 380.256034 -249.341894)
		(end 380.256034 -248.806208)
		(width 0.2032)
		(layer "F.Cu")
		(net "GND")
	)
	(segment
		(start 189.226698 -13.122148)
		(end 189.226698 -12.461748)
		(width 0.3556)
		(layer "F.Cu")
		(net "GND")
	)
	(segment
		(start 459.559914 -309.51678)
		(end 460.664814 -309.51678)
		(width 0.381)
		(layer "F.Cu")
		(net "GND")
	)
	(segment
		(start 436.928514 -307.816758)
		(end 438.033414 -307.816758)
		(width 0.381)
		(layer "F.Cu")
		(net "GND")
	)
	(segment
		(start 429.384714 -221.96679)
		(end 430.489614 -221.96679)
		(width 0.381)
		(layer "F.Cu")
		(net "GND")
	)
	(segment
		(start 460.664814 -210.916774)
		(end 459.559914 -210.916774)
		(width 0.381)
		(layer "F.Cu")
		(net "GND")
	)
	(segment
		(start 90.134694 -281.05608)
		(end 90.134694 -281.59202)
		(width 0.2032)
		(layer "F.Cu")
		(net "GND")
	)
	(segment
		(start 433.484782 -295.916604)
		(end 434.589682 -295.916604)
		(width 0.381)
		(layer "F.Cu")
		(net "GND")
	)
	(segment
		(start 435.823614 -296.766742)
		(end 436.928514 -296.766742)
		(width 0.381)
		(layer "F.Cu")
		(net "GND")
	)
	(segment
		(start 433.484782 -282.316682)
		(end 434.589682 -282.316682)
		(width 0.381)
		(layer "F.Cu")
		(net "GND")
	)
	(segment
		(start 344.183462 -265.592306)
		(end 344.183462 -266.128246)
		(width 0.254)
		(layer "F.Cu")
		(net "GND")
	)
	(segment
		(start 200.632314 -301.01667)
		(end 201.737214 -301.01667)
		(width 0.381)
		(layer "F.Cu")
		(net "GND")
	)
	(segment
		(start 441.028582 -297.616626)
		(end 442.133482 -297.616626)
		(width 0.381)
		(layer "F.Cu")
		(net "GND")
	)
	(segment
		(start 193.088514 -267.866622)
		(end 194.193414 -267.866622)
		(width 0.381)
		(layer "F.Cu")
		(net "GND")
	)
	(segment
		(start 158.813246 -238.966756)
		(end 157.470856 -238.966756)
		(width 0.381)
		(layer "F.Cu")
		(net "GND")
	)
	(segment
		(start 277.607014 -220.266768)
		(end 278.711914 -220.266768)
		(width 0.381)
		(layer "F.Cu")
		(net "GND")
	)
	(segment
		(start 305.443382 -194.766692)
		(end 306.548282 -194.766692)
		(width 0.381)
		(layer "F.Cu")
		(net "GND")
	)
	(segment
		(start 97.073466 -235.506006)
		(end 97.073466 -234.970066)
		(width 0.2032)
		(layer "F.Cu")
		(net "GND")
	)
	(segment
		(start 449.677282 -266.1666)
		(end 448.572382 -266.1666)
		(width 0.381)
		(layer "F.Cu")
		(net "GND")
	)
	(segment
		(start 29.666946 -220.266768)
		(end 30.771846 -220.266768)
		(width 0.381)
		(layer "F.Cu")
		(net "GND")
	)
	(segment
		(start 12.240514 -308.666642)
		(end 13.345414 -308.666642)
		(width 0.381)
		(layer "F.Cu")
		(net "GND")
	)
	(segment
		(start 297.899582 -200.716642)
		(end 299.004482 -200.716642)
		(width 0.381)
		(layer "F.Cu")
		(net "GND")
	)
	(segment
		(start 307.456078 -421.92321)
		(end 307.456078 -421.23741)
		(width 0.3556)
		(layer "F.Cu")
		(net "GND")
	)
	(segment
		(start 14.452346 -388.161276)
		(end 14.426946 -388.135876)
		(width 0.3556)
		(layer "F.Cu")
		(net "GND")
	)
	(segment
		(start 370.85778 -234.69219)
		(end 370.85778 -234.15625)
		(width 0.254)
		(layer "F.Cu")
		(net "GND")
	)
	(segment
		(start 374.61698 -222.76181)
		(end 374.617234 -222.761556)
		(width 0.254)
		(layer "F.Cu")
		(net "GND")
	)
	(segment
		(start 382.245362 -271.289272)
		(end 382.245616 -271.825212)
		(width 0.2032)
		(layer "F.Cu")
		(net "GND")
	)
	(segment
		(start 39.420546 -238.966756)
		(end 38.315646 -238.966756)
		(width 0.381)
		(layer "F.Cu")
		(net "GND")
	)
	(segment
		(start 125.525022 -139.178538)
		(end 125.525022 -139.813538)
		(width 0.3556)
		(layer "F.Cu")
		(net "GND")
	)
	(segment
		(start 110.230666 -217.600276)
		(end 110.230666 -217.064336)
		(width 0.2032)
		(layer "F.Cu")
		(net "GND")
	)
	(segment
		(start 342.844374 -54.747668)
		(end 342.932512 -54.900068)
		(width 0.2032)
		(layer "F.Cu")
		(net "GND")
	)
	(segment
		(start 432.379882 -262.76681)
		(end 433.484782 -262.76681)
		(width 0.381)
		(layer "F.Cu")
		(net "GND")
	)
	(segment
		(start 195.427346 -306.116736)
		(end 196.532246 -306.116736)
		(width 0.381)
		(layer "F.Cu")
		(net "GND")
	)
	(segment
		(start 356.21595 -414.111948)
		(end 355.6 -414.111948)
		(width 0.3556)
		(layer "F.Cu")
		(net "GND")
	)
	(segment
		(start 85.334094 -269.66164)
		(end 85.435694 -269.66164)
		(width 0.2032)
		(layer "F.Cu")
		(net "GND")
	)
	(segment
		(start 161.808414 -211.766658)
		(end 162.913314 -211.766658)
		(width 0.381)
		(layer "F.Cu")
		(net "GND")
	)
	(segment
		(start 301.343314 -292.516814)
		(end 302.664114 -292.516814)
		(width 0.381)
		(layer "F.Cu")
		(net "GND")
	)
	(segment
		(start 173.900846 -292.516814)
		(end 175.259746 -292.516814)
		(width 0.381)
		(layer "F.Cu")
		(net "GND")
	)
	(segment
		(start 44.754546 -214.316564)
		(end 45.859446 -214.316564)
		(width 0.381)
		(layer "F.Cu")
		(net "GND")
	)
	(segment
		(start 65.047114 -305.266598)
		(end 66.152014 -305.266598)
		(width 0.381)
		(layer "F.Cu")
		(net "GND")
	)
	(segment
		(start 119.628666 -227.367084)
		(end 119.628666 -226.831144)
		(width 0.2032)
		(layer "F.Cu")
		(net "GND")
	)
	(segment
		(start 104.121712 -229.808786)
		(end 104.121966 -229.808532)
		(width 0.2032)
		(layer "F.Cu")
		(net "GND")
	)
	(segment
		(start 122.558048 -279.150064)
		(end 122.557794 -279.150318)
		(width 0.254)
		(layer "F.Cu")
		(net "GND")
	)
	(segment
		(start 180.339746 -276.366732)
		(end 181.444646 -276.366732)
		(width 0.381)
		(layer "F.Cu")
		(net "GND")
	)
	(segment
		(start 181.444646 -311.216802)
		(end 180.339746 -311.216802)
		(width 0.381)
		(layer "F.Cu")
		(net "GND")
	)
	(segment
		(start 441.028582 -272.966688)
		(end 442.133482 -272.966688)
		(width 0.381)
		(layer "F.Cu")
		(net "GND")
	)
	(segment
		(start 211.619846 -236.416596)
		(end 212.724746 -236.416596)
		(width 0.381)
		(layer "F.Cu")
		(net "GND")
	)
	(segment
		(start 103.762048 -283.497782)
		(end 103.762048 -284.033468)
		(width 0.254)
		(layer "F.Cu")
		(net "GND")
	)
	(segment
		(start 301.343314 -272.116804)
		(end 302.448214 -272.116804)
		(width 0.381)
		(layer "F.Cu")
		(net "GND")
	)
	(segment
		(start 368.527838 -338.86013)
		(end 369.138962 -338.86013)
		(width 0.381)
		(layer "F.Cu")
		(net "GND")
	)
	(segment
		(start 122.558048 -270.475456)
		(end 122.558048 -271.011396)
		(width 0.254)
		(layer "F.Cu")
		(net "GND")
	)
	(segment
		(start 199.527414 -277.216616)
		(end 200.632314 -277.216616)
		(width 0.381)
		(layer "F.Cu")
		(net "GND")
	)
	(segment
		(start 180.339746 -197.316598)
		(end 181.444646 -197.316598)
		(width 0.381)
		(layer "F.Cu")
		(net "GND")
	)
	(segment
		(start 353.581716 -267.219938)
		(end 353.581462 -267.220192)
		(width 0.254)
		(layer "F.Cu")
		(net "GND")
	)
	(segment
		(start 386.474716 -255.825498)
		(end 386.00507 -255.547368)
		(width 0.254)
		(layer "F.Cu")
		(net "GND")
	)
	(segment
		(start 62.30493 -19.268948)
		(end 62.92088 -19.268948)
		(width 0.3556)
		(layer "F.Cu")
		(net "GND")
	)
	(segment
		(start 413.192214 -265.316716)
		(end 414.297114 -265.316716)
		(width 0.381)
		(layer "F.Cu")
		(net "GND")
	)
	(segment
		(start 275.268182 -238.116618)
		(end 274.163282 -238.116618)
		(width 0.381)
		(layer "F.Cu")
		(net "GND")
	)
	(segment
		(start 346.063316 -259.081016)
		(end 346.063316 -259.616956)
		(width 0.2032)
		(layer "F.Cu")
		(net "GND")
	)
	(segment
		(start 38.822884 -355.372924)
		(end 39.165022 -355.372924)
		(width 0.2032)
		(layer "F.Cu")
		(net "GND")
	)
	(segment
		(start 333.510128 -54.558946)
		(end 333.400146 -54.747668)
		(width 0.2032)
		(layer "F.Cu")
		(net "GND")
	)
	(segment
		(start 414.297114 -260.21665)
		(end 415.402014 -260.21665)
		(width 0.381)
		(layer "F.Cu")
		(net "GND")
	)
	(segment
		(start 85.523324 -250.428506)
		(end 85.178646 -250.428506)
		(width 0.2032)
		(layer "F.Cu")
		(net "GND")
	)
	(segment
		(start 262.519414 -250.016772)
		(end 263.624314 -250.016772)
		(width 0.381)
		(layer "F.Cu")
		(net "GND")
	)
	(segment
		(start 77.181202 -345.802712)
		(end 77.509878 -345.474036)
		(width 0.254)
		(layer "F.Cu")
		(net "GND")
	)
	(segment
		(start 420.736014 -201.56678)
		(end 421.840914 -201.56678)
		(width 0.381)
		(layer "F.Cu")
		(net "GND")
	)
	(segment
		(start 435.823614 -236.416596)
		(end 436.928514 -236.416596)
		(width 0.381)
		(layer "F.Cu")
		(net "GND")
	)
	(segment
		(start 420.736014 -248.31675)
		(end 421.840914 -248.31675)
		(width 0.381)
		(layer "F.Cu")
		(net "GND")
	)
	(segment
		(start 376.271536 -106.525568)
		(end 376.48515 -106.739182)
		(width 0.3556)
		(layer "F.Cu")
		(net "GND")
	)
	(segment
		(start 136.075166 -244.458744)
		(end 136.075166 -243.922804)
		(width 0.254)
		(layer "F.Cu")
		(net "GND")
	)
	(segment
		(start 184.439814 -266.1666)
		(end 185.544714 -266.1666)
		(width 0.381)
		(layer "F.Cu")
		(net "GND")
	)
	(segment
		(start 383.545334 -222.48368)
		(end 383.545334 -221.94774)
		(width 0.254)
		(layer "F.Cu")
		(net "GND")
	)
	(segment
		(start 133.255766 -228.180646)
		(end 133.255766 -227.64496)
		(width 0.2032)
		(layer "F.Cu")
		(net "GND")
	)
	(segment
		(start 374.61698 -223.297496)
		(end 374.61698 -222.76181)
		(width 0.254)
		(layer "F.Cu")
		(net "GND")
	)
	(segment
		(start 381.19558 -233.064304)
		(end 381.19558 -232.528364)
		(width 0.2032)
		(layer "F.Cu")
		(net "GND")
	)
	(segment
		(start 347.214698 -58.609992)
		(end 347.214698 -57.954926)
		(width 0.2032)
		(layer "F.Cu")
		(net "GND")
	)
	(segment
		(start 167.461946 -296.766742)
		(end 166.357046 -296.766742)
		(width 0.381)
		(layer "F.Cu")
		(net "GND")
	)
	(segment
		(start 342.19388 -248.527824)
		(end 342.19388 -247.992138)
		(width 0.2032)
		(layer "F.Cu")
		(net "GND")
	)
	(segment
		(start 289.250882 -267.866622)
		(end 290.355782 -267.866622)
		(width 0.381)
		(layer "F.Cu")
		(net "GND")
	)
	(segment
		(start 340.901782 -57.605168)
		(end 340.401402 -58.020204)
		(width 0.254)
		(layer "F.Cu")
		(net "GND")
	)
	(segment
		(start 370.388134 -237.133892)
		(end 370.38788 -237.133638)
		(width 0.254)
		(layer "F.Cu")
		(net "GND")
	)
	(segment
		(start 254.975614 -242.3668)
		(end 256.080514 -242.3668)
		(width 0.381)
		(layer "F.Cu")
		(net "GND")
	)
	(segment
		(start 109.290866 -238.225838)
		(end 109.290866 -238.761524)
		(width 0.254)
		(layer "F.Cu")
		(net "GND")
	)
	(segment
		(start 60.947046 -307.816758)
		(end 62.051946 -307.816758)
		(width 0.381)
		(layer "F.Cu")
		(net "GND")
	)
	(segment
		(start 12.240514 -210.066636)
		(end 13.345414 -210.066636)
		(width 0.381)
		(layer "F.Cu")
		(net "GND")
	)
	(segment
		(start 263.624314 -260.21665)
		(end 264.729214 -260.21665)
		(width 0.381)
		(layer "F.Cu")
		(net "GND")
	)
	(segment
		(start 214.065358 -68.846446)
		(end 213.813644 -68.594732)
		(width 0.3556)
		(layer "F.Cu")
		(net "GND")
	)
	(segment
		(start 335.615534 -243.644928)
		(end 335.615534 -243.108988)
		(width 0.2032)
		(layer "F.Cu")
		(net "GND")
	)
	(segment
		(start 135.605266 -231.714548)
		(end 135.605266 -232.250488)
		(width 0.254)
		(layer "F.Cu")
		(net "GND")
	)
	(segment
		(start 272.273014 -287.416748)
		(end 271.168114 -287.416748)
		(width 0.381)
		(layer "F.Cu")
		(net "GND")
	)
	(segment
		(start 207.071214 -247.466612)
		(end 208.176114 -247.466612)
		(width 0.381)
		(layer "F.Cu")
		(net "GND")
	)
	(segment
		(start 254.975614 -313.766708)
		(end 256.080514 -313.766708)
		(width 0.381)
		(layer "F.Cu")
		(net "GND")
	)
	(segment
		(start 414.297114 -311.216802)
		(end 415.597848 -311.216802)
		(width 0.381)
		(layer "F.Cu")
		(net "GND")
	)
	(segment
		(start 382.715516 -287.288986)
		(end 382.715262 -287.28924)
		(width 0.254)
		(layer "F.Cu")
		(net "GND")
	)
	(segment
		(start 113.519712 -216.250774)
		(end 113.519966 -216.25052)
		(width 0.254)
		(layer "F.Cu")
		(net "GND")
	)
	(segment
		(start 300.238414 -214.316564)
		(end 301.343314 -214.316564)
		(width 0.381)
		(layer "F.Cu")
		(net "GND")
	)
	(segment
		(start 312.987182 -299.316648)
		(end 314.092082 -299.316648)
		(width 0.381)
		(layer "F.Cu")
		(net "GND")
	)
	(segment
		(start 179.105814 -238.116618)
		(end 178.000914 -238.116618)
		(width 0.381)
		(layer "F.Cu")
		(net "GND")
	)
	(segment
		(start 40.256968 -8.320024)
		(end 40.256968 -9.424924)
		(width 0.3556)
		(layer "F.Cu")
		(net "GND")
	)
	(segment
		(start 287.98012 -392.569954)
		(end 287.98012 -393.776454)
		(width 0.4572)
		(layer "F.Cu")
		(net "GND")
	)
	(segment
		(start 342.537542 -335.541112)
		(end 342.198452 -335.541112)
		(width 0.2032)
		(layer "F.Cu")
		(net "GND")
	)
	(segment
		(start 22.51583 -429.351948)
		(end 21.90623 -429.351948)
		(width 0.3556)
		(layer "F.Cu")
		(net "GND")
	)
	(segment
		(start 336.399632 -39.443152)
		(end 336.899758 -39.295324)
		(width 0.2032)
		(layer "F.Cu")
		(net "GND")
	)
	(segment
		(start 357.810562 -272.917158)
		(end 357.810562 -273.453098)
		(width 0.254)
		(layer "F.Cu")
		(net "GND")
	)
	(segment
		(start 422.945814 -309.51678)
		(end 421.840914 -309.51678)
		(width 0.381)
		(layer "F.Cu")
		(net "GND")
	)
	(segment
		(start 347.472762 -257.175254)
		(end 347.472762 -256.639314)
		(width 0.2032)
		(layer "F.Cu")
		(net "GND")
	)
	(segment
		(start 361.569762 -274.54479)
		(end 361.569762 -275.08073)
		(width 0.254)
		(layer "F.Cu")
		(net "GND")
	)
	(segment
		(start 343.60358 -222.76181)
		(end 343.603834 -222.761556)
		(width 0.254)
		(layer "F.Cu")
		(net "GND")
	)
	(segment
		(start 18.679414 -249.166634)
		(end 19.784314 -249.166634)
		(width 0.381)
		(layer "F.Cu")
		(net "GND")
	)
	(segment
		(start 370.967762 -281.591512)
		(end 370.968016 -281.591766)
		(width 0.254)
		(layer "F.Cu")
		(net "GND")
	)
	(segment
		(start 121.618248 -284.033468)
		(end 121.617994 -284.033722)
		(width 0.254)
		(layer "F.Cu")
		(net "GND")
	)
	(segment
		(start 339.84438 -247.714262)
		(end 339.84438 -247.178322)
		(width 0.2032)
		(layer "F.Cu")
		(net "GND")
	)
	(segment
		(start 48.854614 -289.966654)
		(end 49.959514 -289.966654)
		(width 0.381)
		(layer "F.Cu")
		(net "GND")
	)
	(segment
		(start 15.684246 -251.716794)
		(end 14.579346 -251.716794)
		(width 0.381)
		(layer "F.Cu")
		(net "GND")
	)
	(segment
		(start 352.531934 -224.111566)
		(end 352.531934 -223.575626)
		(width 0.2032)
		(layer "F.Cu")
		(net "GND")
	)
	(segment
		(start 11.135614 -230.466646)
		(end 12.240514 -230.466646)
		(width 0.381)
		(layer "F.Cu")
		(net "GND")
	)
	(segment
		(start 348.302834 -220.041724)
		(end 348.302834 -219.506038)
		(width 0.254)
		(layer "F.Cu")
		(net "GND")
	)
	(segment
		(start 7.035546 -236.416596)
		(end 8.140446 -236.416596)
		(width 0.381)
		(layer "F.Cu")
		(net "GND")
	)
	(segment
		(start 28.961334 -170.029886)
		(end 28.961334 -169.400728)
		(width 0.381)
		(layer "F.Cu")
		(net "GND")
	)
	(segment
		(start 263.726676 -129.439924)
		(end 263.726676 -128.652016)
		(width 0.3556)
		(layer "F.Cu")
		(net "GND")
	)
	(segment
		(start 300.022514 -220.266768)
		(end 301.343314 -220.266768)
		(width 0.381)
		(layer "F.Cu")
		(net "GND")
	)
	(segment
		(start 342.194134 -242.017042)
		(end 342.194134 -241.481102)
		(width 0.2032)
		(layer "F.Cu")
		(net "GND")
	)
	(segment
		(start 138.534648 -285.6611)
		(end 138.534394 -285.661354)
		(width 0.2032)
		(layer "F.Cu")
		(net "GND")
	)
	(segment
		(start 34.871914 -289.966654)
		(end 33.767014 -289.966654)
		(width 0.381)
		(layer "F.Cu")
		(net "GND")
	)
	(segment
		(start 385.424934 -222.48368)
		(end 385.424934 -221.94774)
		(width 0.2032)
		(layer "F.Cu")
		(net "GND")
	)
	(segment
		(start 103.181912 -216.250774)
		(end 103.182166 -216.25052)
		(width 0.254)
		(layer "F.Cu")
		(net "GND")
	)
	(segment
		(start 312.987182 -294.216582)
		(end 314.092082 -294.216582)
		(width 0.381)
		(layer "F.Cu")
		(net "GND")
	)
	(segment
		(start 335.255616 -287.56737)
		(end 335.255616 -288.102802)
		(width 0.254)
		(layer "F.Cu")
		(net "GND")
	)
	(segment
		(start 165.048946 -276.366732)
		(end 166.357046 -276.366732)
		(width 0.381)
		(layer "F.Cu")
		(net "GND")
	)
	(segment
		(start 134.305294 -274.54479)
		(end 134.305294 -275.080476)
		(width 0.2032)
		(layer "F.Cu")
		(net "GND")
	)
	(segment
		(start 380.365762 -263.68629)
		(end 380.366016 -263.686544)
		(width 0.2032)
		(layer "F.Cu")
		(net "GND")
	)
	(segment
		(start 299.6946 -343.760044)
		(end 299.6946 -344.700352)
		(width 0.508)
		(layer "F.Cu")
		(net "GND")
	)
	(segment
		(start 359.58018 -216.250774)
		(end 359.580434 -216.25052)
		(width 0.254)
		(layer "F.Cu")
		(net "GND")
	)
	(segment
		(start 96.133412 -240.388902)
		(end 96.133412 -239.853216)
		(width 0.2032)
		(layer "F.Cu")
		(net "GND")
	)
	(segment
		(start 8.140446 -246.616728)
		(end 9.245346 -246.616728)
		(width 0.381)
		(layer "F.Cu")
		(net "GND")
	)
	(segment
		(start 453.121014 -212.616796)
		(end 452.016114 -212.616796)
		(width 0.381)
		(layer "F.Cu")
		(net "GND")
	)
	(segment
		(start 118.798848 -285.125414)
		(end 118.798848 -285.661354)
		(width 0.254)
		(layer "F.Cu")
		(net "GND")
	)
	(segment
		(start 354.051362 -279.428194)
		(end 354.051362 -279.96388)
		(width 0.254)
		(layer "F.Cu")
		(net "GND")
	)
	(segment
		(start 368.618516 -270.475456)
		(end 368.618262 -271.011396)
		(width 0.2032)
		(layer "F.Cu")
		(net "GND")
	)
	(segment
		(start 38.812724 -358.529636)
		(end 38.812724 -359.20045)
		(width 0.381)
		(layer "F.Cu")
		(net "GND")
	)
	(segment
		(start 356.401116 -272.103342)
		(end 356.401116 -272.639028)
		(width 0.2032)
		(layer "F.Cu")
		(net "GND")
	)
	(segment
		(start 39.420546 -217.716608)
		(end 38.315646 -217.716608)
		(width 0.381)
		(layer "F.Cu")
		(net "GND")
	)
	(segment
		(start 165.252146 -240.666778)
		(end 166.357046 -240.666778)
		(width 0.381)
		(layer "F.Cu")
		(net "GND")
	)
	(segment
		(start 353.581716 -275.35886)
		(end 353.581716 -275.8948)
		(width 0.2032)
		(layer "F.Cu")
		(net "GND")
	)
	(segment
		(start 305.443382 -267.866622)
		(end 306.548282 -267.866622)
		(width 0.381)
		(layer "F.Cu")
		(net "GND")
	)
	(segment
		(start 185.544714 -194.766692)
		(end 186.649614 -194.766692)
		(width 0.381)
		(layer "F.Cu")
		(net "GND")
	)
	(segment
		(start 452.016114 -206.666592)
		(end 450.911214 -206.666592)
		(width 0.381)
		(layer "F.Cu")
		(net "GND")
	)
	(segment
		(start 92.484448 -286.7533)
		(end 92.484448 -287.28924)
		(width 0.254)
		(layer "F.Cu")
		(net "GND")
	)
	(segment
		(start 308.887114 -265.316716)
		(end 309.992014 -265.316716)
		(width 0.381)
		(layer "F.Cu")
		(net "GND")
	)
	(segment
		(start 342.773762 -279.428194)
		(end 342.773762 -279.964134)
		(width 0.254)
		(layer "F.Cu")
		(net "GND")
	)
	(segment
		(start 293.799514 -278.066754)
		(end 292.694614 -278.066754)
		(width 0.381)
		(layer "F.Cu")
		(net "GND")
	)
	(segment
		(start 294.904414 -197.316598)
		(end 293.799514 -197.316598)
		(width 0.381)
		(layer "F.Cu")
		(net "GND")
	)
	(segment
		(start 249.786394 -90.65514)
		(end 249.140726 -90.65514)
		(width 0.3556)
		(layer "F.Cu")
		(net "GND")
	)
	(segment
		(start 103.762048 -267.219938)
		(end 103.761794 -267.220192)
		(width 0.254)
		(layer "F.Cu")
		(net "GND")
	)
	(segment
		(start 168.883584 -355.996494)
		(end 168.449498 -356.43058)
		(width 0.2032)
		(layer "F.Cu")
		(net "GND")
	)
	(segment
		(start 123.387866 -245.27256)
		(end 123.387612 -245.272306)
		(width 0.2032)
		(layer "F.Cu")
		(net "GND")
	)
	(segment
		(start 116.449094 -282.683966)
		(end 116.449094 -283.219652)
		(width 0.254)
		(layer "F.Cu")
		(net "GND")
	)
	(segment
		(start 89.084912 -214.622888)
		(end 89.084658 -214.622634)
		(width 0.2032)
		(layer "F.Cu")
		(net "GND")
	)
	(segment
		(start 194.193414 -261.066788)
		(end 193.088514 -261.066788)
		(width 0.381)
		(layer "F.Cu")
		(net "GND")
	)
	(segment
		(start 40.256968 -7.215124)
		(end 40.256968 -8.320024)
		(width 0.3556)
		(layer "F.Cu")
		(net "GND")
	)
	(segment
		(start 131.375912 -223.297496)
		(end 131.375912 -222.76181)
		(width 0.254)
		(layer "F.Cu")
		(net "GND")
	)
	(segment
		(start 347.36278 -242.830858)
		(end 347.36278 -242.295172)
		(width 0.2032)
		(layer "F.Cu")
		(net "GND")
	)
	(segment
		(start 136.184894 -277.800562)
		(end 136.184894 -278.336502)
		(width 0.254)
		(layer "F.Cu")
		(net "GND")
	)
	(segment
		(start 102.5398 -102.118668)
		(end 102.464362 -102.04323)
		(width 0.3556)
		(layer "F.Cu")
		(net "GND")
	)
	(segment
		(start 44.754546 -281.466798)
		(end 45.859446 -281.466798)
		(width 0.381)
		(layer "F.Cu")
		(net "GND")
	)
	(segment
		(start 356.761034 -231.436164)
		(end 356.761034 -230.900478)
		(width 0.2032)
		(layer "F.Cu")
		(net "GND")
	)
	(segment
		(start 161.808414 -280.61666)
		(end 162.913314 -280.61666)
		(width 0.381)
		(layer "F.Cu")
		(net "GND")
	)
	(segment
		(start 95.303848 -257.45313)
		(end 95.303848 -257.988816)
		(width 0.2032)
		(layer "F.Cu")
		(net "GND")
	)
	(segment
		(start 411.958282 -228.766624)
		(end 410.853382 -228.766624)
		(width 0.381)
		(layer "F.Cu")
		(net "GND")
	)
	(segment
		(start 460.664814 -265.316716)
		(end 459.559914 -265.316716)
		(width 0.381)
		(layer "F.Cu")
		(net "GND")
	)
	(segment
		(start 57.503314 -230.466646)
		(end 58.608214 -230.466646)
		(width 0.381)
		(layer "F.Cu")
		(net "GND")
	)
	(segment
		(start 196.532246 -242.3668)
		(end 197.637146 -242.3668)
		(width 0.381)
		(layer "F.Cu")
		(net "GND")
	)
	(segment
		(start 12.240514 -299.316648)
		(end 13.345414 -299.316648)
		(width 0.381)
		(layer "F.Cu")
		(net "GND")
	)
	(segment
		(start 131.956048 -283.497782)
		(end 131.956048 -284.033468)
		(width 0.254)
		(layer "F.Cu")
		(net "GND")
	)
	(segment
		(start 338.904834 -229.808532)
		(end 338.904834 -229.272846)
		(width 0.2032)
		(layer "F.Cu")
		(net "GND")
	)
	(segment
		(start 453.121014 -267.016738)
		(end 452.016114 -267.016738)
		(width 0.381)
		(layer "F.Cu")
		(net "GND")
	)
	(segment
		(start 333.155798 -18.39722)
		(end 334.174846 -18.39722)
		(width 0.3556)
		(layer "F.Cu")
		(net "GND")
	)
	(segment
		(start 263.624314 -197.316598)
		(end 264.729214 -197.316598)
		(width 0.381)
		(layer "F.Cu")
		(net "GND")
	)
	(segment
		(start 456.116182 -250.866656)
		(end 455.011282 -250.866656)
		(width 0.381)
		(layer "F.Cu")
		(net "GND")
	)
	(segment
		(start 96.243648 -284.033468)
		(end 96.243394 -284.033722)
		(width 0.254)
		(layer "F.Cu")
		(net "GND")
	)
	(segment
		(start 287.360614 -317.166752)
		(end 286.255714 -317.166752)
		(width 0.381)
		(layer "F.Cu")
		(net "GND")
	)
	(segment
		(start 267.724382 -196.466714)
		(end 268.829282 -196.466714)
		(width 0.381)
		(layer "F.Cu")
		(net "GND")
	)
	(segment
		(start 427.230032 -392.155934)
		(end 426.595032 -392.155934)
		(width 0.3556)
		(layer "F.Cu")
		(net "GND")
	)
	(segment
		(start 175.30953 -424.398948)
		(end 175.91913 -424.398948)
		(width 0.3556)
		(layer "F.Cu")
		(net "GND")
	)
	(segment
		(start 429.384714 -298.466764)
		(end 430.489614 -298.466764)
		(width 0.381)
		(layer "F.Cu")
		(net "GND")
	)
	(segment
		(start 110.340648 -282.405582)
		(end 110.340394 -282.405836)
		(width 0.254)
		(layer "F.Cu")
		(net "GND")
	)
	(segment
		(start 22.24151 -170.292014)
		(end 22.24151 -169.604436)
		(width 0.381)
		(layer "F.Cu")
		(net "GND")
	)
	(segment
		(start 102.352094 -277.800562)
		(end 102.352094 -278.336248)
		(width 0.254)
		(layer "F.Cu")
		(net "GND")
	)
	(segment
		(start 433.484782 -267.866622)
		(end 434.589682 -267.866622)
		(width 0.381)
		(layer "F.Cu")
		(net "GND")
	)
	(segment
		(start 254.975614 -304.416714)
		(end 256.080514 -304.416714)
		(width 0.381)
		(layer "F.Cu")
		(net "GND")
	)
	(segment
		(start 11.135614 -308.666642)
		(end 12.240514 -308.666642)
		(width 0.381)
		(layer "F.Cu")
		(net "GND")
	)
	(segment
		(start 18.679414 -228.766624)
		(end 19.784314 -228.766624)
		(width 0.381)
		(layer "F.Cu")
		(net "GND")
	)
	(segment
		(start 260.180582 -269.566644)
		(end 259.075682 -269.566644)
		(width 0.381)
		(layer "F.Cu")
		(net "GND")
	)
	(segment
		(start 129.496312 -244.458744)
		(end 129.496312 -243.922804)
		(width 0.2032)
		(layer "F.Cu")
		(net "GND")
	)
	(segment
		(start 105.641394 -268.847824)
		(end 105.641394 -269.38351)
		(width 0.254)
		(layer "F.Cu")
		(net "GND")
	)
	(segment
		(start 274.163282 -230.466646)
		(end 275.268182 -230.466646)
		(width 0.381)
		(layer "F.Cu")
		(net "GND")
	)
	(segment
		(start 277.607014 -289.11677)
		(end 278.711914 -289.11677)
		(width 0.381)
		(layer "F.Cu")
		(net "GND")
	)
	(segment
		(start 334.205834 -226.553268)
		(end 334.205834 -226.017328)
		(width 0.2032)
		(layer "F.Cu")
		(net "GND")
	)
	(segment
		(start 339.84438 -216.250774)
		(end 339.844634 -216.25052)
		(width 0.254)
		(layer "F.Cu")
		(net "GND")
	)
	(segment
		(start 249.46483 -86.35746)
		(end 250.194064 -87.086694)
		(width 0.3556)
		(layer "F.Cu")
		(net "GND")
	)
	(segment
		(start 439.923682 -216.866724)
		(end 441.028582 -216.866724)
		(width 0.381)
		(layer "F.Cu")
		(net "GND")
	)
	(segment
		(start 372.377716 -275.35886)
		(end 372.377462 -275.8948)
		(width 0.2032)
		(layer "F.Cu")
		(net "GND")
	)
	(segment
		(start 11.135614 -207.51673)
		(end 12.240514 -207.51673)
		(width 0.381)
		(layer "F.Cu")
		(net "GND")
	)
	(segment
		(start 185.544714 -205.816708)
		(end 184.439814 -205.816708)
		(width 0.381)
		(layer "F.Cu")
		(net "GND")
	)
	(segment
		(start 341.37727 -53.149246)
		(end 341.921338 -53.148992)
		(width 0.2032)
		(layer "F.Cu")
		(net "GND")
	)
	(segment
		(start 444.472314 -283.166566)
		(end 445.577214 -283.166566)
		(width 0.381)
		(layer "F.Cu")
		(net "GND")
	)
	(segment
		(start 272.273014 -311.216802)
		(end 271.168114 -311.216802)
		(width 0.381)
		(layer "F.Cu")
		(net "GND")
	)
	(segment
		(start 159.918146 -268.71676)
		(end 158.813246 -268.71676)
		(width 0.381)
		(layer "F.Cu")
		(net "GND")
	)
	(segment
		(start 344.07348 -238.76127)
		(end 344.07348 -238.225584)
		(width 0.2032)
		(layer "F.Cu")
		(net "GND")
	)
	(segment
		(start 294.904414 -276.366732)
		(end 293.799514 -276.366732)
		(width 0.381)
		(layer "F.Cu")
		(net "GND")
	)
	(segment
		(start 136.075166 -231.436418)
		(end 136.075166 -230.900478)
		(width 0.254)
		(layer "F.Cu")
		(net "GND")
	)
	(segment
		(start 375.197116 -287.288986)
		(end 375.196862 -287.28924)
		(width 0.254)
		(layer "F.Cu")
		(net "GND")
	)
	(segment
		(start 44.754546 -197.316598)
		(end 45.859446 -197.316598)
		(width 0.381)
		(layer "F.Cu")
		(net "GND")
	)
	(segment
		(start 278.711914 -292.516814)
		(end 279.816814 -292.516814)
		(width 0.381)
		(layer "F.Cu")
		(net "GND")
	)
	(segment
		(start 409.485338 -310.366664)
		(end 410.853382 -310.366664)
		(width 0.381)
		(layer "F.Cu")
		(net "GND")
	)
	(segment
		(start 380.25578 -236.319822)
		(end 380.25578 -235.783882)
		(width 0.2032)
		(layer "F.Cu")
		(net "GND")
	)
	(segment
		(start 260.180582 -299.316648)
		(end 259.075682 -299.316648)
		(width 0.381)
		(layer "F.Cu")
		(net "GND")
	)
	(segment
		(start 60.947046 -311.216802)
		(end 62.267846 -311.216802)
		(width 0.381)
		(layer "F.Cu")
		(net "GND")
	)
	(segment
		(start 308.887114 -201.56678)
		(end 309.992014 -201.56678)
		(width 0.381)
		(layer "F.Cu")
		(net "GND")
	)
	(segment
		(start 425.940982 -245.76659)
		(end 427.045882 -245.76659)
		(width 0.381)
		(layer "F.Cu")
		(net "GND")
	)
	(segment
		(start 278.711914 -223.666558)
		(end 279.816814 -223.666558)
		(width 0.381)
		(layer "F.Cu")
		(net "GND")
	)
	(segment
		(start 413.192214 -268.71676)
		(end 414.297114 -268.71676)
		(width 0.381)
		(layer "F.Cu")
		(net "GND")
	)
	(segment
		(start 375.55678 -234.69219)
		(end 375.557034 -234.691936)
		(width 0.2032)
		(layer "F.Cu")
		(net "GND")
	)
	(segment
		(start 211.619846 -263.616694)
		(end 212.724746 -263.616694)
		(width 0.381)
		(layer "F.Cu")
		(net "GND")
	)
	(segment
		(start 342.735154 -40.461692)
		(end 343.006934 -40.931592)
		(width 0.254)
		(layer "F.Cu")
		(net "GND")
	)
	(segment
		(start 369.558316 -283.497782)
		(end 369.558316 -284.033468)
		(width 0.254)
		(layer "F.Cu")
		(net "GND")
	)
	(segment
		(start 246.567452 -89.143586)
		(end 245.311168 -89.143586)
		(width 0.3556)
		(layer "F.Cu")
		(net "GND")
	)
	(segment
		(start 363.492796 -358.93375)
		(end 363.046518 -358.93375)
		(width 0.3556)
		(layer "F.Cu")
		(net "GND")
	)
	(segment
		(start 166.357046 -208.366614)
		(end 167.690546 -208.366614)
		(width 0.381)
		(layer "F.Cu")
		(net "GND")
	)
	(segment
		(start 208.176114 -272.966688)
		(end 209.281014 -272.966688)
		(width 0.381)
		(layer "F.Cu")
		(net "GND")
	)
	(segment
		(start 425.940982 -211.766658)
		(end 424.836082 -211.766658)
		(width 0.381)
		(layer "F.Cu")
		(net "GND")
	)
	(segment
		(start 162.913314 -207.51673)
		(end 164.280596 -207.51673)
		(width 0.381)
		(layer "F.Cu")
		(net "GND")
	)
	(segment
		(start 188.988446 -287.416748)
		(end 190.093346 -287.416748)
		(width 0.381)
		(layer "F.Cu")
		(net "GND")
	)
	(segment
		(start 281.707082 -271.266666)
		(end 282.811982 -271.266666)
		(width 0.381)
		(layer "F.Cu")
		(net "GND")
	)
	(segment
		(start 347.36278 -226.553268)
		(end 347.36278 -226.017582)
		(width 0.254)
		(layer "F.Cu")
		(net "GND")
	)
	(segment
		(start 409.540202 -205.816708)
		(end 410.853382 -205.816708)
		(width 0.381)
		(layer "F.Cu")
		(net "GND")
	)
	(segment
		(start 33.767014 -261.066788)
		(end 34.871914 -261.066788)
		(width 0.381)
		(layer "F.Cu")
		(net "GND")
	)
	(segment
		(start 166.357046 -223.666558)
		(end 165.252146 -223.666558)
		(width 0.381)
		(layer "F.Cu")
		(net "GND")
	)
	(segment
		(start 267.724382 -210.066636)
		(end 268.829282 -210.066636)
		(width 0.381)
		(layer "F.Cu")
		(net "GND")
	)
	(segment
		(start 23.431754 -399.932144)
		(end 24.447754 -399.932144)
		(width 0.4572)
		(layer "F.Cu")
		(net "GND")
	)
	(segment
		(start 436.928514 -317.166752)
		(end 438.033414 -317.166752)
		(width 0.381)
		(layer "F.Cu")
		(net "GND")
	)
	(segment
		(start 407.858214 -279.766776)
		(end 406.753314 -279.766776)
		(width 0.381)
		(layer "F.Cu")
		(net "GND")
	)
	(segment
		(start 160.211516 -216.016586)
		(end 158.813246 -216.016586)
		(width 0.381)
		(layer "F.Cu")
		(net "GND")
	)
	(segment
		(start 270.063214 -281.466798)
		(end 271.168114 -281.466798)
		(width 0.381)
		(layer "F.Cu")
		(net "GND")
	)
	(segment
		(start 384.96367 -248.794524)
		(end 384.962654 -248.798588)
		(width 0.254)
		(layer "F.Cu")
		(net "GND")
	)
	(segment
		(start 125.847094 -276.172676)
		(end 125.847094 -276.708616)
		(width 0.2032)
		(layer "F.Cu")
		(net "GND")
	)
	(segment
		(start 328.244962 -53.952902)
		(end 328.194162 -54.003702)
		(width 0.2032)
		(layer "F.Cu")
		(net "GND")
	)
	(segment
		(start 26.496772 -416.83305)
		(end 26.662888 -416.666934)
		(width 0.3556)
		(layer "F.Cu")
		(net "GND")
	)
	(segment
		(start 94.723966 -220.041724)
		(end 94.723966 -219.506038)
		(width 0.254)
		(layer "F.Cu")
		(net "GND")
	)
	(segment
		(start 193.088514 -308.666642)
		(end 194.193414 -308.666642)
		(width 0.381)
		(layer "F.Cu")
		(net "GND")
	)
	(segment
		(start 361.45978 -240.66754)
		(end 361.460034 -240.667286)
		(width 0.254)
		(layer "F.Cu")
		(net "GND")
	)
	(segment
		(start 38.315646 -270.416782)
		(end 37.210746 -270.416782)
		(width 0.381)
		(layer "F.Cu")
		(net "GND")
	)
	(segment
		(start 43.85691 -8.320024)
		(end 43.85691 -9.424924)
		(width 0.3556)
		(layer "F.Cu")
		(net "GND")
	)
	(segment
		(start 337.604862 -268.84757)
		(end 337.604862 -269.38351)
		(width 0.2032)
		(layer "F.Cu")
		(net "GND")
	)
	(segment
		(start 413.192214 -306.116736)
		(end 414.297114 -306.116736)
		(width 0.381)
		(layer "F.Cu")
		(net "GND")
	)
	(segment
		(start 108.820712 -216.78646)
		(end 108.820712 -216.250774)
		(width 0.254)
		(layer "F.Cu")
		(net "GND")
	)
	(segment
		(start 185.544714 -224.516696)
		(end 186.649614 -224.516696)
		(width 0.381)
		(layer "F.Cu")
		(net "GND")
	)
	(segment
		(start 410.853382 -249.166634)
		(end 411.958282 -249.166634)
		(width 0.381)
		(layer "F.Cu")
		(net "GND")
	)
	(segment
		(start 344.07348 -237.133638)
		(end 344.07348 -236.597952)
		(width 0.2032)
		(layer "F.Cu")
		(net "GND")
	)
	(segment
		(start 348.882716 -255.825498)
		(end 348.882716 -256.361438)
		(width 0.2032)
		(layer "F.Cu")
		(net "GND")
	)
	(segment
		(start 65.047114 -219.41663)
		(end 66.367914 -219.41663)
		(width 0.381)
		(layer "F.Cu")
		(net "GND")
	)
	(segment
		(start 101.302566 -241.202972)
		(end 101.302566 -240.667286)
		(width 0.254)
		(layer "F.Cu")
		(net "GND")
	)
	(segment
		(start 110.230666 -224.111566)
		(end 110.230666 -223.575626)
		(width 0.2032)
		(layer "F.Cu")
		(net "GND")
	)
	(segment
		(start 129.966212 -245.272306)
		(end 129.966212 -244.73662)
		(width 0.2032)
		(layer "F.Cu")
		(net "GND")
	)
	(segment
		(start 44.754546 -270.416782)
		(end 45.859446 -270.416782)
		(width 0.381)
		(layer "F.Cu")
		(net "GND")
	)
	(segment
		(start 41.310814 -310.366664)
		(end 42.415714 -310.366664)
		(width 0.381)
		(layer "F.Cu")
		(net "GND")
	)
	(segment
		(start 193.088514 -233.86669)
		(end 191.983614 -233.86669)
		(width 0.381)
		(layer "F.Cu")
		(net "GND")
	)
	(segment
		(start 383.02184 -344.742008)
		(end 383.340102 -344.742008)
		(width 0.2032)
		(layer "F.Cu")
		(net "GND")
	)
	(segment
		(start 87.315294 -287.567116)
		(end 87.315294 -288.103056)
		(width 0.2032)
		(layer "F.Cu")
		(net "GND")
	)
	(segment
		(start 378.016516 -267.755624)
		(end 378.016262 -267.755878)
		(width 0.254)
		(layer "F.Cu")
		(net "GND")
	)
	(segment
		(start 297.899582 -230.466646)
		(end 299.004482 -230.466646)
		(width 0.381)
		(layer "F.Cu")
		(net "GND")
	)
	(segment
		(start 57.503314 -291.666676)
		(end 58.824114 -291.666676)
		(width 0.381)
		(layer "F.Cu")
		(net "GND")
	)
	(segment
		(start 393.046966 -8.320024)
		(end 393.046966 -7.215124)
		(width 0.3556)
		(layer "F.Cu")
		(net "GND")
	)
	(segment
		(start 14.579346 -231.316784)
		(end 15.684246 -231.316784)
		(width 0.381)
		(layer "F.Cu")
		(net "GND")
	)
	(segment
		(start 127.616966 -229.808532)
		(end 127.616966 -229.272846)
		(width 0.2032)
		(layer "F.Cu")
		(net "GND")
	)
	(segment
		(start 42.415714 -282.316682)
		(end 41.310814 -282.316682)
		(width 0.381)
		(layer "F.Cu")
		(net "GND")
	)
	(segment
		(start 282.811982 -282.316682)
		(end 283.916882 -282.316682)
		(width 0.381)
		(layer "F.Cu")
		(net "GND")
	)
	(segment
		(start 377.43638 -236.319822)
		(end 377.436634 -236.319568)
		(width 0.2032)
		(layer "F.Cu")
		(net "GND")
	)
	(segment
		(start 215.719914 -221.116652)
		(end 216.824814 -221.116652)
		(width 0.381)
		(layer "F.Cu")
		(net "GND")
	)
	(segment
		(start 167.461946 -199.01662)
		(end 166.357046 -199.01662)
		(width 0.381)
		(layer "F.Cu")
		(net "GND")
	)
	(segment
		(start 375.666762 -255.011682)
		(end 376.606816 -255.547622)
		(width 0.2032)
		(layer "F.Cu")
		(net "GND")
	)
	(segment
		(start 384.485134 -225.739198)
		(end 384.485134 -225.203258)
		(width 0.254)
		(layer "F.Cu")
		(net "GND")
	)
	(segment
		(start 419.826186 -134.130034)
		(end 420.282116 -134.130034)
		(width 0.381)
		(layer "F.Cu")
		(net "GND")
	)
	(segment
		(start 307.594254 -238.966756)
		(end 308.887114 -238.966756)
		(width 0.381)
		(layer "F.Cu")
		(net "GND")
	)
	(segment
		(start 290.355782 -232.166668)
		(end 291.460682 -232.166668)
		(width 0.381)
		(layer "F.Cu")
		(net "GND")
	)
	(segment
		(start 91.544648 -260.708902)
		(end 91.544648 -261.244588)
		(width 0.2032)
		(layer "F.Cu")
		(net "GND")
	)
	(segment
		(start 377.43638 -239.57534)
		(end 377.43638 -239.0394)
		(width 0.2032)
		(layer "F.Cu")
		(net "GND")
	)
	(segment
		(start 375.718578 -102.921562)
		(end 375.718578 -102.054152)
		(width 0.3556)
		(layer "F.Cu")
		(net "GND")
	)
	(segment
		(start 276.373082 -316.316614)
		(end 275.268182 -316.316614)
		(width 0.381)
		(layer "F.Cu")
		(net "GND")
	)
	(segment
		(start 363.33938 -222.76181)
		(end 363.339634 -222.761556)
		(width 0.254)
		(layer "F.Cu")
		(net "GND")
	)
	(segment
		(start 342.664034 -220.041724)
		(end 342.664034 -219.506038)
		(width 0.254)
		(layer "F.Cu")
		(net "GND")
	)
	(segment
		(start 122.087894 -266.405868)
		(end 122.088148 -266.941808)
		(width 0.254)
		(layer "F.Cu")
		(net "GND")
	)
	(segment
		(start 341.72398 -220.041978)
		(end 341.724234 -220.041724)
		(width 0.254)
		(layer "F.Cu")
		(net "GND")
	)
	(segment
		(start 393.046966 -11.26998)
		(end 393.046966 -10.16508)
		(width 0.3556)
		(layer "F.Cu")
		(net "GND")
	)
	(segment
		(start 157.599126 -285.716726)
		(end 157.573726 -285.742126)
		(width 0.381)
		(layer "F.Cu")
		(net "GND")
	)
	(segment
		(start 14.579346 -307.816758)
		(end 15.684246 -307.816758)
		(width 0.381)
		(layer "F.Cu")
		(net "GND")
	)
	(segment
		(start 433.484782 -230.466646)
		(end 434.589682 -230.466646)
		(width 0.381)
		(layer "F.Cu")
		(net "GND")
	)
	(segment
		(start 38.315646 -242.3668)
		(end 37.210746 -242.3668)
		(width 0.381)
		(layer "F.Cu")
		(net "GND")
	)
	(segment
		(start 311.882282 -295.916604)
		(end 312.987182 -295.916604)
		(width 0.381)
		(layer "F.Cu")
		(net "GND")
	)
	(segment
		(start 343.133934 -220.855794)
		(end 343.133934 -220.319854)
		(width 0.2032)
		(layer "F.Cu")
		(net "GND")
	)
	(segment
		(start 173.900846 -261.916672)
		(end 172.795946 -261.916672)
		(width 0.381)
		(layer "F.Cu")
		(net "GND")
	)
	(segment
		(start 342.773762 -285.939484)
		(end 342.773762 -286.475424)
		(width 0.2032)
		(layer "F.Cu")
		(net "GND")
	)
	(segment
		(start 285.150814 -311.216802)
		(end 286.255714 -311.216802)
		(width 0.381)
		(layer "F.Cu")
		(net "GND")
	)
	(segment
		(start 407.677874 -236.397038)
		(end 407.658316 -236.416596)
		(width 0.381)
		(layer "F.Cu")
		(net "GND")
	)
	(segment
		(start 379.31598 -219.506292)
		(end 379.316234 -219.506038)
		(width 0.254)
		(layer "F.Cu")
		(net "GND")
	)
	(segment
		(start 202.971146 -265.316716)
		(end 204.076046 -265.316716)
		(width 0.381)
		(layer "F.Cu")
		(net "GND")
	)
	(segment
		(start 308.887114 -238.966756)
		(end 310.207914 -238.966756)
		(width 0.381)
		(layer "F.Cu")
		(net "GND")
	)
	(segment
		(start 429.384714 -225.36658)
		(end 430.489614 -225.36658)
		(width 0.381)
		(layer "F.Cu")
		(net "GND")
	)
	(segment
		(start 166.357046 -289.11677)
		(end 167.461946 -289.11677)
		(width 0.381)
		(layer "F.Cu")
		(net "GND")
	)
	(segment
		(start 281.707082 -289.966654)
		(end 282.811982 -289.966654)
		(width 0.381)
		(layer "F.Cu")
		(net "GND")
	)
	(segment
		(start 348.772734 -238.761524)
		(end 348.77248 -238.76127)
		(width 0.2032)
		(layer "F.Cu")
		(net "GND")
	)
	(segment
		(start 175.005746 -273.587972)
		(end 174.777146 -273.816572)
		(width 0.381)
		(layer "F.Cu")
		(net "GND")
	)
	(segment
		(start 449.677282 -310.366664)
		(end 448.572382 -310.366664)
		(width 0.381)
		(layer "F.Cu")
		(net "GND")
	)
	(segment
		(start 3.579368 -73.694798)
		(end 3.579368 -72.92721)
		(width 0.3556)
		(layer "F.Cu")
		(net "GND")
	)
	(segment
		(start 272.273014 -315.46673)
		(end 271.168114 -315.46673)
		(width 0.381)
		(layer "F.Cu")
		(net "GND")
	)
	(segment
		(start 97.93859 -30.434788)
		(end 97.31756 -30.434788)
		(width 0.3556)
		(layer "F.Cu")
		(net "GND")
	)
	(segment
		(start 436.928514 -298.466764)
		(end 438.033414 -298.466764)
		(width 0.381)
		(layer "F.Cu")
		(net "GND")
	)
	(segment
		(start 353.581462 -270.47571)
		(end 353.581462 -271.011396)
		(width 0.254)
		(layer "F.Cu")
		(net "GND")
	)
	(segment
		(start 158.813246 -223.666558)
		(end 157.708346 -223.666558)
		(width 0.381)
		(layer "F.Cu")
		(net "GND")
	)
	(segment
		(start 190.093346 -210.916774)
		(end 188.988446 -210.916774)
		(width 0.381)
		(layer "F.Cu")
		(net "GND")
	)
	(segment
		(start 134.665466 -245.27256)
		(end 134.665212 -245.272306)
		(width 0.2032)
		(layer "F.Cu")
		(net "GND")
	)
	(segment
		(start 329.89647 -39.295324)
		(end 328.895964 -39.295324)
		(width 0.2032)
		(layer "F.Cu")
		(net "GND")
	)
	(segment
		(start 127.257048 -286.7533)
		(end 127.257048 -287.288986)
		(width 0.254)
		(layer "F.Cu")
		(net "GND")
	)
	(segment
		(start 295.3766 -364.945168)
		(end 295.721278 -364.60049)
		(width 0.2032)
		(layer "F.Cu")
		(net "GND")
	)
	(segment
		(start 112.579912 -226.553268)
		(end 112.579912 -226.017582)
		(width 0.254)
		(layer "F.Cu")
		(net "GND")
	)
	(segment
		(start 340.78418 -234.69219)
		(end 340.78418 -234.156504)
		(width 0.254)
		(layer "F.Cu")
		(net "GND")
	)
	(segment
		(start 92.484448 -284.033468)
		(end 92.484194 -284.033722)
		(width 0.254)
		(layer "F.Cu")
		(net "GND")
	)
	(segment
		(start 344.07348 -240.388902)
		(end 344.07348 -239.853216)
		(width 0.2032)
		(layer "F.Cu")
		(net "GND")
	)
	(segment
		(start 157.708346 -227.066602)
		(end 158.813246 -227.066602)
		(width 0.381)
		(layer "F.Cu")
		(net "GND")
	)
	(segment
		(start 281.707082 -305.266598)
		(end 282.811982 -305.266598)
		(width 0.381)
		(layer "F.Cu")
		(net "GND")
	)
	(segment
		(start 178.000914 -310.366664)
		(end 179.105814 -310.366664)
		(width 0.381)
		(layer "F.Cu")
		(net "GND")
	)
	(segment
		(start 118.328694 -279.428194)
		(end 118.328694 -279.964134)
		(width 0.254)
		(layer "F.Cu")
		(net "GND")
	)
	(segment
		(start 129.606294 -256.807462)
		(end 129.606548 -257.175254)
		(width 0.2032)
		(layer "F.Cu")
		(net "GND")
	)
	(segment
		(start 49.959514 -312.91657)
		(end 51.064414 -312.91657)
		(width 0.381)
		(layer "F.Cu")
		(net "GND")
	)
	(segment
		(start 276.373082 -194.766692)
		(end 275.268182 -194.766692)
		(width 0.381)
		(layer "F.Cu")
		(net "GND")
	)
	(segment
		(start 275.268182 -314.616592)
		(end 274.163282 -314.616592)
		(width 0.381)
		(layer "F.Cu")
		(net "GND")
	)
	(segment
		(start 285.150814 -199.01662)
		(end 286.255714 -199.01662)
		(width 0.381)
		(layer "F.Cu")
		(net "GND")
	)
	(segment
		(start 115.106704 -362.618528)
		(end 115.716304 -362.618528)
		(width 0.381)
		(layer "F.Cu")
		(net "GND")
	)
	(segment
		(start 27.328114 -221.116652)
		(end 28.433014 -221.116652)
		(width 0.381)
		(layer "F.Cu")
		(net "GND")
	)
	(segment
		(start 304.122582 -221.116652)
		(end 305.443382 -221.116652)
		(width 0.381)
		(layer "F.Cu")
		(net "GND")
	)
	(segment
		(start 117.749066 -214.344758)
		(end 117.749066 -213.732618)
		(width 0.254)
		(layer "F.Cu")
		(net "GND")
	)
	(segment
		(start 38.315646 -261.916672)
		(end 37.210746 -261.916672)
		(width 0.381)
		(layer "F.Cu")
		(net "GND")
	)
	(segment
		(start 131.486148 -281.591766)
		(end 131.486148 -281.59202)
		(width 0.254)
		(layer "F.Cu")
		(net "GND")
	)
	(segment
		(start 277.607014 -233.016806)
		(end 278.711914 -233.016806)
		(width 0.381)
		(layer "F.Cu")
		(net "GND")
	)
	(segment
		(start 26.223214 -288.266632)
		(end 27.328114 -288.266632)
		(width 0.381)
		(layer "F.Cu")
		(net "GND")
	)
	(segment
		(start 12.240514 -238.116618)
		(end 13.345414 -238.116618)
		(width 0.381)
		(layer "F.Cu")
		(net "GND")
	)
	(segment
		(start 14.579346 -229.616762)
		(end 15.684246 -229.616762)
		(width 0.381)
		(layer "F.Cu")
		(net "GND")
	)
	(segment
		(start 96.133412 -232.250234)
		(end 96.133412 -231.714548)
		(width 0.2032)
		(layer "F.Cu")
		(net "GND")
	)
	(segment
		(start 52.298346 -233.016806)
		(end 53.403246 -233.016806)
		(width 0.381)
		(layer "F.Cu")
		(net "GND")
	)
	(segment
		(start 134.305294 -258.802886)
		(end 134.305548 -258.80314)
		(width 0.2032)
		(layer "F.Cu")
		(net "GND")
	)
	(segment
		(start 119.628666 -224.111566)
		(end 119.628666 -223.575626)
		(width 0.2032)
		(layer "F.Cu")
		(net "GND")
	)
	(segment
		(start 179.2224 -94.738698)
		(end 179.2224 -95.367348)
		(width 0.3556)
		(layer "F.Cu")
		(net "GND")
	)
	(segment
		(start 373.317516 -267.219938)
		(end 373.317262 -267.755878)
		(width 0.2032)
		(layer "F.Cu")
		(net "GND")
	)
	(segment
		(start 380.25578 -244.458744)
		(end 380.256034 -244.45849)
		(width 0.2032)
		(layer "F.Cu")
		(net "GND")
	)
	(segment
		(start 365.21898 -226.553268)
		(end 365.21898 -226.017582)
		(width 0.254)
		(layer "F.Cu")
		(net "GND")
	)
	(segment
		(start 375.557034 -229.808532)
		(end 375.557034 -229.272846)
		(width 0.2032)
		(layer "F.Cu")
		(net "GND")
	)
	(segment
		(start 101.772466 -246.900446)
		(end 101.772466 -246.36476)
		(width 0.2032)
		(layer "F.Cu")
		(net "GND")
	)
	(segment
		(start 364.27918 -220.041978)
		(end 364.279434 -220.041724)
		(width 0.254)
		(layer "F.Cu")
		(net "GND")
	)
	(segment
		(start 337.604862 -260.708902)
		(end 337.604862 -261.244842)
		(width 0.2032)
		(layer "F.Cu")
		(net "GND")
	)
	(segment
		(start 405.648414 -227.066602)
		(end 406.753314 -227.066602)
		(width 0.381)
		(layer "F.Cu")
		(net "GND")
	)
	(segment
		(start 459.559914 -229.616762)
		(end 458.455014 -229.616762)
		(width 0.381)
		(layer "F.Cu")
		(net "GND")
	)
	(segment
		(start 293.799514 -199.01662)
		(end 292.694614 -199.01662)
		(width 0.381)
		(layer "F.Cu")
		(net "GND")
	)
	(segment
		(start 409.748482 -294.216582)
		(end 410.853382 -294.216582)
		(width 0.381)
		(layer "F.Cu")
		(net "GND")
	)
	(segment
		(start 204.076046 -315.46673)
		(end 205.180946 -315.46673)
		(width 0.381)
		(layer "F.Cu")
		(net "GND")
	)
	(segment
		(start 418.408866 -182.555642)
		(end 418.180012 -182.555642)
		(width 0.2032)
		(layer "F.Cu")
		(net "GND")
	)
	(segment
		(start 256.080514 -309.51678)
		(end 257.185414 -309.51678)
		(width 0.381)
		(layer "F.Cu")
		(net "GND")
	)
	(segment
		(start 346.532962 -281.591766)
		(end 346.533216 -281.59202)
		(width 0.254)
		(layer "F.Cu")
		(net "GND")
	)
	(segment
		(start 266.619482 -194.766692)
		(end 267.724382 -194.766692)
		(width 0.381)
		(layer "F.Cu")
		(net "GND")
	)
	(segment
		(start 89.555066 -223.575626)
		(end 89.555066 -224.111566)
		(width 0.254)
		(layer "F.Cu")
		(net "GND")
	)
	(segment
		(start 335.725262 -283.497782)
		(end 335.725262 -284.033722)
		(width 0.254)
		(layer "F.Cu")
		(net "GND")
	)
	(segment
		(start 101.302312 -246.08663)
		(end 101.302566 -246.086376)
		(width 0.2032)
		(layer "F.Cu")
		(net "GND")
	)
	(segment
		(start 53.403246 -258.516628)
		(end 54.508146 -258.516628)
		(width 0.381)
		(layer "F.Cu")
		(net "GND")
	)
	(segment
		(start 43.520614 -224.516696)
		(end 42.415714 -224.516696)
		(width 0.381)
		(layer "F.Cu")
		(net "GND")
	)
	(segment
		(start 188.988446 -278.066754)
		(end 190.093346 -278.066754)
		(width 0.381)
		(layer "F.Cu")
		(net "GND")
	)
	(segment
		(start 131.015994 -264.500106)
		(end 131.015994 -264.50036)
		(width 0.2032)
		(layer "F.Cu")
		(net "GND")
	)
	(segment
		(start 383.185416 -270.167862)
		(end 383.185416 -270.19758)
		(width 0.2032)
		(layer "F.Cu")
		(net "GND")
	)
	(segment
		(start 157.801818 -69.86397)
		(end 157.00121 -69.86397)
		(width 0.3556)
		(layer "F.Cu")
		(net "GND")
	)
	(segment
		(start 293.799514 -210.916774)
		(end 292.694614 -210.916774)
		(width 0.381)
		(layer "F.Cu")
		(net "GND")
	)
	(segment
		(start 137.484866 -242.017042)
		(end 136.545066 -241.481102)
		(width 0.254)
		(layer "F.Cu")
		(net "GND")
	)
	(segment
		(start 336.665316 -278.614378)
		(end 336.665062 -279.150318)
		(width 0.2032)
		(layer "F.Cu")
		(net "GND")
	)
	(segment
		(start 137.594594 -262.336534)
		(end 137.594594 -262.872474)
		(width 0.254)
		(layer "F.Cu")
		(net "GND")
	)
	(segment
		(start 92.844112 -223.297496)
		(end 92.844112 -222.76181)
		(width 0.254)
		(layer "F.Cu")
		(net "GND")
	)
	(segment
		(start 89.664794 -275.35886)
		(end 89.664794 -275.8948)
		(width 0.2032)
		(layer "F.Cu")
		(net "GND")
	)
	(segment
		(start 354.331778 -400.328638)
		(end 353.68865 -400.328638)
		(width 0.3556)
		(layer "F.Cu")
		(net "GND")
	)
	(segment
		(start 428.279814 -296.766742)
		(end 429.384714 -296.766742)
		(width 0.381)
		(layer "F.Cu")
		(net "GND")
	)
	(segment
		(start 341.918798 -48.450246)
		(end 342.190578 -48.920146)
		(width 0.254)
		(layer "F.Cu")
		(net "GND")
	)
	(segment
		(start 380.725934 -238.761524)
		(end 380.725934 -238.225584)
		(width 0.2032)
		(layer "F.Cu")
		(net "GND")
	)
	(segment
		(start 439.923682 -306.96662)
		(end 441.028582 -306.96662)
		(width 0.381)
		(layer "F.Cu")
		(net "GND")
	)
	(segment
		(start 366.738916 -276.986492)
		(end 366.738916 -277.522432)
		(width 0.254)
		(layer "F.Cu")
		(net "GND")
	)
	(segment
		(start 297.899582 -310.366664)
		(end 299.004482 -310.366664)
		(width 0.381)
		(layer "F.Cu")
		(net "GND")
	)
	(segment
		(start 129.136648 -263.96442)
		(end 129.136648 -264.499852)
		(width 0.2032)
		(layer "F.Cu")
		(net "GND")
	)
	(segment
		(start 413.192214 -221.96679)
		(end 414.297114 -221.96679)
		(width 0.381)
		(layer "F.Cu")
		(net "GND")
	)
	(segment
		(start 278.711914 -229.616762)
		(end 279.816814 -229.616762)
		(width 0.381)
		(layer "F.Cu")
		(net "GND")
	)
	(segment
		(start 162.913314 -250.866656)
		(end 161.808414 -250.866656)
		(width 0.381)
		(layer "F.Cu")
		(net "GND")
	)
	(segment
		(start 431.36693 -8.320024)
		(end 431.36693 -7.215124)
		(width 0.3556)
		(layer "F.Cu")
		(net "GND")
	)
	(segment
		(start 99.422712 -244.458744)
		(end 99.422966 -244.45849)
		(width 0.2032)
		(layer "F.Cu")
		(net "GND")
	)
	(segment
		(start 344.07348 -243.644674)
		(end 344.07348 -243.108988)
		(width 0.2032)
		(layer "F.Cu")
		(net "GND")
	)
	(segment
		(start 337.604862 -265.592306)
		(end 337.604862 -266.128246)
		(width 0.254)
		(layer "F.Cu")
		(net "GND")
	)
	(segment
		(start 49.959514 -211.766658)
		(end 51.064414 -211.766658)
		(width 0.381)
		(layer "F.Cu")
		(net "GND")
	)
	(segment
		(start 460.664814 -236.416596)
		(end 459.559914 -236.416596)
		(width 0.381)
		(layer "F.Cu")
		(net "GND")
	)
	(segment
		(start 462.555082 -211.766658)
		(end 463.659982 -211.766658)
		(width 0.381)
		(layer "F.Cu")
		(net "GND")
	)
	(segment
		(start 114.243612 -365.558324)
		(end 114.243612 -366.167924)
		(width 0.381)
		(layer "F.Cu")
		(net "GND")
	)
	(segment
		(start 196.532246 -234.716574)
		(end 197.637146 -234.716574)
		(width 0.381)
		(layer "F.Cu")
		(net "GND")
	)
	(segment
		(start 183.86044 -12.817348)
		(end 183.53532 -12.492228)
		(width 0.3556)
		(layer "F.Cu")
		(net "GND")
	)
	(segment
		(start 285.150814 -251.716794)
		(end 286.255714 -251.716794)
		(width 0.381)
		(layer "F.Cu")
		(net "GND")
	)
	(segment
		(start 334.174846 -18.39722)
		(end 334.174846 -17.935702)
		(width 0.3556)
		(layer "F.Cu")
		(net "GND")
	)
	(segment
		(start 5.644642 -100.81895)
		(end 5.99186 -101.166168)
		(width 0.3556)
		(layer "F.Cu")
		(net "GND")
	)
	(segment
		(start 282.811982 -280.61666)
		(end 283.916882 -280.61666)
		(width 0.381)
		(layer "F.Cu")
		(net "GND")
	)
	(segment
		(start 344.63355 -40.931846)
		(end 344.362532 -40.461692)
		(width 0.254)
		(layer "F.Cu")
		(net "GND")
	)
	(segment
		(start 180.339746 -231.316784)
		(end 181.444646 -231.316784)
		(width 0.381)
		(layer "F.Cu")
		(net "GND")
	)
	(segment
		(start 169.352214 -215.166702)
		(end 170.457114 -215.166702)
		(width 0.381)
		(layer "F.Cu")
		(net "GND")
	)
	(segment
		(start 436.928514 -225.36658)
		(end 438.033414 -225.36658)
		(width 0.381)
		(layer "F.Cu")
		(net "GND")
	)
	(segment
		(start 457.221082 -228.766624)
		(end 456.116182 -228.766624)
		(width 0.381)
		(layer "F.Cu")
		(net "GND")
	)
	(segment
		(start 459.559914 -295.06672)
		(end 460.664814 -295.06672)
		(width 0.381)
		(layer "F.Cu")
		(net "GND")
	)
	(segment
		(start 266.619482 -226.216718)
		(end 267.724382 -226.216718)
		(width 0.381)
		(layer "F.Cu")
		(net "GND")
	)
	(segment
		(start 182.549546 -311.216802)
		(end 181.444646 -311.216802)
		(width 0.381)
		(layer "F.Cu")
		(net "GND")
	)
	(segment
		(start 48.854614 -267.866622)
		(end 49.959514 -267.866622)
		(width 0.381)
		(layer "F.Cu")
		(net "GND")
	)
	(segment
		(start 112.110266 -215.436958)
		(end 112.110012 -215.436704)
		(width 0.2032)
		(layer "F.Cu")
		(net "GND")
	)
	(segment
		(start 453.121014 -289.11677)
		(end 452.016114 -289.11677)
		(width 0.381)
		(layer "F.Cu")
		(net "GND")
	)
	(segment
		(start 56.182514 -219.41663)
		(end 57.503314 -219.41663)
		(width 0.381)
		(layer "F.Cu")
		(net "GND")
	)
	(segment
		(start 337.699858 -50.050446)
		(end 337.299808 -50.450496)
		(width 0.2032)
		(layer "F.Cu")
		(net "GND")
	)
	(segment
		(start 410.853382 -286.56661)
		(end 411.958282 -286.56661)
		(width 0.381)
		(layer "F.Cu")
		(net "GND")
	)
	(segment
		(start 456.116182 -245.76659)
		(end 455.011282 -245.76659)
		(width 0.381)
		(layer "F.Cu")
		(net "GND")
	)
	(segment
		(start 433.484782 -213.46668)
		(end 434.589682 -213.46668)
		(width 0.381)
		(layer "F.Cu")
		(net "GND")
	)
	(segment
		(start 250.490228 -91.709748)
		(end 250.490228 -91.358974)
		(width 0.3556)
		(layer "F.Cu")
		(net "GND")
	)
	(segment
		(start 107.129326 -93.665548)
		(end 106.429048 -93.665548)
		(width 0.3556)
		(layer "F.Cu")
		(net "GND")
	)
	(segment
		(start 289.250882 -207.51673)
		(end 290.355782 -207.51673)
		(width 0.381)
		(layer "F.Cu")
		(net "GND")
	)
	(segment
		(start 194.193414 -215.166702)
		(end 193.088514 -215.166702)
		(width 0.381)
		(layer "F.Cu")
		(net "GND")
	)
	(segment
		(start 286.255714 -233.016806)
		(end 287.360614 -233.016806)
		(width 0.381)
		(layer "F.Cu")
		(net "GND")
	)
	(segment
		(start 282.811982 -308.666642)
		(end 283.916882 -308.666642)
		(width 0.381)
		(layer "F.Cu")
		(net "GND")
	)
	(segment
		(start 291.460682 -266.1666)
		(end 290.355782 -266.1666)
		(width 0.381)
		(layer "F.Cu")
		(net "GND")
	)
	(segment
		(start 409.748482 -262.76681)
		(end 410.853382 -262.76681)
		(width 0.381)
		(layer "F.Cu")
		(net "GND")
	)
	(segment
		(start 124.437648 -272.103342)
		(end 124.437394 -272.639282)
		(width 0.2032)
		(layer "F.Cu")
		(net "GND")
	)
	(segment
		(start 449.677282 -267.866622)
		(end 448.572382 -267.866622)
		(width 0.381)
		(layer "F.Cu")
		(net "GND")
	)
	(segment
		(start 367.878868 -408.319986)
		(end 368.31524 -408.319986)
		(width 0.3556)
		(layer "F.Cu")
		(net "GND")
	)
	(segment
		(start 272.273014 -285.716726)
		(end 271.168114 -285.716726)
		(width 0.381)
		(layer "F.Cu")
		(net "GND")
	)
	(segment
		(start 355.82098 -220.041978)
		(end 355.821234 -220.041724)
		(width 0.254)
		(layer "F.Cu")
		(net "GND")
	)
	(segment
		(start 94.833694 -281.05608)
		(end 94.833694 -281.59202)
		(width 0.254)
		(layer "F.Cu")
		(net "GND")
	)
	(segment
		(start 357.70058 -216.78646)
		(end 357.70058 -216.250774)
		(width 0.254)
		(layer "F.Cu")
		(net "GND")
	)
	(segment
		(start 170.63593 -433.923948)
		(end 171.24553 -433.923948)
		(width 0.3556)
		(layer "F.Cu")
		(net "GND")
	)
	(segment
		(start 308.887114 -270.416782)
		(end 309.992014 -270.416782)
		(width 0.381)
		(layer "F.Cu")
		(net "GND")
	)
	(segment
		(start 161.808414 -314.616592)
		(end 162.913314 -314.616592)
		(width 0.381)
		(layer "F.Cu")
		(net "GND")
	)
	(segment
		(start 19.784314 -308.666642)
		(end 18.679414 -308.666642)
		(width 0.381)
		(layer "F.Cu")
		(net "GND")
	)
	(segment
		(start 373.67718 -216.250774)
		(end 373.677434 -216.25052)
		(width 0.254)
		(layer "F.Cu")
		(net "GND")
	)
	(segment
		(start 43.520614 -288.266632)
		(end 42.415714 -288.266632)
		(width 0.381)
		(layer "F.Cu")
		(net "GND")
	)
	(segment
		(start 136.655048 -282.405582)
		(end 136.654794 -282.405836)
		(width 0.254)
		(layer "F.Cu")
		(net "GND")
	)
	(segment
		(start 187.883546 -273.816572)
		(end 188.988446 -273.816572)
		(width 0.381)
		(layer "F.Cu")
		(net "GND")
	)
	(segment
		(start 51.467004 -11.26998)
		(end 51.467004 -10.16508)
		(width 0.3556)
		(layer "F.Cu")
		(net "GND")
	)
	(segment
		(start 198.81469 -71.582788)
		(end 199.42429 -71.582788)
		(width 0.3556)
		(layer "F.Cu")
		(net "GND")
	)
	(segment
		(start 133.255512 -216.250774)
		(end 133.255766 -216.25052)
		(width 0.254)
		(layer "F.Cu")
		(net "GND")
	)
	(segment
		(start 263.624314 -295.06672)
		(end 264.729214 -295.06672)
		(width 0.381)
		(layer "F.Cu")
		(net "GND")
	)
	(segment
		(start 370.497862 -264.500106)
		(end 370.497862 -264.50036)
		(width 0.2032)
		(layer "F.Cu")
		(net "GND")
	)
	(segment
		(start 290.355782 -250.866656)
		(end 291.460682 -250.866656)
		(width 0.381)
		(layer "F.Cu")
		(net "GND")
	)
	(segment
		(start 132.425694 -281.591512)
		(end 132.425948 -281.591766)
		(width 0.254)
		(layer "F.Cu")
		(net "GND")
	)
	(segment
		(start 347.36278 -223.297496)
		(end 347.36278 -222.76181)
		(width 0.254)
		(layer "F.Cu")
		(net "GND")
	)
	(segment
		(start 19.784314 -221.116652)
		(end 18.679414 -221.116652)
		(width 0.381)
		(layer "F.Cu")
		(net "GND")
	)
	(segment
		(start 435.823614 -265.316716)
		(end 436.928514 -265.316716)
		(width 0.381)
		(layer "F.Cu")
		(net "GND")
	)
	(segment
		(start 433.484782 -266.1666)
		(end 434.589682 -266.1666)
		(width 0.381)
		(layer "F.Cu")
		(net "GND")
	)
	(segment
		(start 173.98365 -365.38281)
		(end 173.98365 -366.33023)
		(width 0.3556)
		(layer "F.Cu")
		(net "GND")
	)
	(segment
		(start 418.885878 -183.032654)
		(end 418.408866 -182.555642)
		(width 0.2032)
		(layer "F.Cu")
		(net "GND")
	)
	(segment
		(start 413.192214 -251.716794)
		(end 414.297114 -251.716794)
		(width 0.381)
		(layer "F.Cu")
		(net "GND")
	)
	(segment
		(start 459.559914 -306.116736)
		(end 460.664814 -306.116736)
		(width 0.381)
		(layer "F.Cu")
		(net "GND")
	)
	(segment
		(start 267.724382 -241.516662)
		(end 268.829282 -241.516662)
		(width 0.381)
		(layer "F.Cu")
		(net "GND")
	)
	(segment
		(start 339.84438 -242.295172)
		(end 339.844634 -242.294918)
		(width 0.2032)
		(layer "F.Cu")
		(net "GND")
	)
	(segment
		(start 165.252146 -258.516628)
		(end 166.357046 -258.516628)
		(width 0.381)
		(layer "F.Cu")
		(net "GND")
	)
	(segment
		(start 369.558316 -282.405582)
		(end 369.558062 -282.405836)
		(width 0.254)
		(layer "F.Cu")
		(net "GND")
	)
	(segment
		(start 32.591502 -167.297354)
		(end 32.591502 -166.777162)
		(width 0.381)
		(layer "F.Cu")
		(net "GND")
	)
	(segment
		(start 167.461946 -201.56678)
		(end 166.357046 -201.56678)
		(width 0.381)
		(layer "F.Cu")
		(net "GND")
	)
	(segment
		(start 98.123248 -278.614378)
		(end 98.123248 -279.150318)
		(width 0.254)
		(layer "F.Cu")
		(net "GND")
	)
	(segment
		(start 207.071214 -280.61666)
		(end 208.176114 -280.61666)
		(width 0.381)
		(layer "F.Cu")
		(net "GND")
	)
	(segment
		(start 128.086866 -245.27256)
		(end 128.086612 -245.272306)
		(width 0.2032)
		(layer "F.Cu")
		(net "GND")
	)
	(segment
		(start 149.352 -35.794188)
		(end 149.397974 -35.840162)
		(width 0.3556)
		(layer "F.Cu")
		(net "GND")
	)
	(segment
		(start 41.01465 -103.977948)
		(end 41.6306 -103.977948)
		(width 0.3556)
		(layer "F.Cu")
		(net "GND")
	)
	(segment
		(start 457.221082 -297.616626)
		(end 456.116182 -297.616626)
		(width 0.381)
		(layer "F.Cu")
		(net "GND")
	)
	(segment
		(start 99.063048 -280.242264)
		(end 99.062794 -280.778204)
		(width 0.254)
		(layer "F.Cu")
		(net "GND")
	)
	(segment
		(start 278.711914 -246.616728)
		(end 279.816814 -246.616728)
		(width 0.381)
		(layer "F.Cu")
		(net "GND")
	)
	(segment
		(start 414.297114 -258.516628)
		(end 415.402014 -258.516628)
		(width 0.381)
		(layer "F.Cu")
		(net "GND")
	)
	(segment
		(start 296.794682 -211.766658)
		(end 297.899582 -211.766658)
		(width 0.381)
		(layer "F.Cu")
		(net "GND")
	)
	(segment
		(start 262.519414 -307.816758)
		(end 263.624314 -307.816758)
		(width 0.381)
		(layer "F.Cu")
		(net "GND")
	)
	(segment
		(start 210.160108 -102.93604)
		(end 209.54492 -102.93604)
		(width 0.3556)
		(layer "F.Cu")
		(net "GND")
	)
	(segment
		(start 130.906012 -233.877866)
		(end 130.906012 -233.34218)
		(width 0.2032)
		(layer "F.Cu")
		(net "GND")
	)
	(segment
		(start 425.940982 -288.266632)
		(end 424.836082 -288.266632)
		(width 0.381)
		(layer "F.Cu")
		(net "GND")
	)
	(segment
		(start 275.268182 -233.86669)
		(end 274.163282 -233.86669)
		(width 0.381)
		(layer "F.Cu")
		(net "GND")
	)
	(segment
		(start 428.279814 -223.666558)
		(end 429.384714 -223.666558)
		(width 0.381)
		(layer "F.Cu")
		(net "GND")
	)
	(segment
		(start 365.689134 -214.344758)
		(end 365.689134 -213.732618)
		(width 0.254)
		(layer "F.Cu")
		(net "GND")
	)
	(segment
		(start 18.679414 -294.216582)
		(end 19.784314 -294.216582)
		(width 0.381)
		(layer "F.Cu")
		(net "GND")
	)
	(segment
		(start 339.484716 -260.708902)
		(end 339.484716 -261.244588)
		(width 0.2032)
		(layer "F.Cu")
		(net "GND")
	)
	(segment
		(start 90.604848 -281.869896)
		(end 90.605102 -281.87015)
		(width 0.254)
		(layer "F.Cu")
		(net "GND")
	)
	(segment
		(start 125.377448 -286.7533)
		(end 125.377448 -287.288986)
		(width 0.254)
		(layer "F.Cu")
		(net "GND")
	)
	(segment
		(start 103.291894 -279.428194)
		(end 103.291894 -279.964134)
		(width 0.2032)
		(layer "F.Cu")
		(net "GND")
	)
	(segment
		(start 53.403246 -296.766742)
		(end 54.508146 -296.766742)
		(width 0.381)
		(layer "F.Cu")
		(net "GND")
	)
	(segment
		(start 98.482912 -222.76181)
		(end 98.483166 -222.761556)
		(width 0.254)
		(layer "F.Cu")
		(net "GND")
	)
	(segment
		(start 297.096434 -423.56532)
		(end 297.485562 -423.954448)
		(width 0.3556)
		(layer "F.Cu")
		(net "GND")
	)
	(segment
		(start 58.608214 -261.066788)
		(end 57.503314 -261.066788)
		(width 0.381)
		(layer "F.Cu")
		(net "GND")
	)
	(segment
		(start 49.959514 -305.266598)
		(end 51.064414 -305.266598)
		(width 0.381)
		(layer "F.Cu")
		(net "GND")
	)
	(segment
		(start 108.820966 -229.808532)
		(end 108.820966 -229.272846)
		(width 0.2032)
		(layer "F.Cu")
		(net "GND")
	)
	(segment
		(start 441.028582 -244.066568)
		(end 442.133482 -244.066568)
		(width 0.381)
		(layer "F.Cu")
		(net "GND")
	)
	(segment
		(start 35.976814 -275.516594)
		(end 34.871914 -275.516594)
		(width 0.381)
		(layer "F.Cu")
		(net "GND")
	)
	(segment
		(start 59.842146 -248.31675)
		(end 60.947046 -248.31675)
		(width 0.381)
		(layer "F.Cu")
		(net "GND")
	)
	(segment
		(start 181.444646 -238.966756)
		(end 182.549546 -238.966756)
		(width 0.381)
		(layer "F.Cu")
		(net "GND")
	)
	(segment
		(start 380.365762 -258.2672)
		(end 380.365762 -258.802886)
		(width 0.2032)
		(layer "F.Cu")
		(net "GND")
	)
	(segment
		(start 285.150814 -206.666592)
		(end 286.255714 -206.666592)
		(width 0.381)
		(layer "F.Cu")
		(net "GND")
	)
	(segment
		(start 439.923682 -266.1666)
		(end 441.028582 -266.1666)
		(width 0.381)
		(layer "F.Cu")
		(net "GND")
	)
	(segment
		(start 272.273014 -289.11677)
		(end 271.168114 -289.11677)
		(width 0.381)
		(layer "F.Cu")
		(net "GND")
	)
	(segment
		(start 433.166774 -11.26998)
		(end 433.166774 -12.37488)
		(width 0.3556)
		(layer "F.Cu")
		(net "GND")
	)
	(segment
		(start 385.97205 -29.581348)
		(end 385.97205 -29.181298)
		(width 0.3556)
		(layer "F.Cu")
		(net "GND")
	)
	(segment
		(start 108.351066 -214.344758)
		(end 108.351066 -213.732618)
		(width 0.254)
		(layer "F.Cu")
		(net "GND")
	)
	(segment
		(start 88.255094 -276.172676)
		(end 87.78494 -275.8948)
		(width 0.254)
		(layer "F.Cu")
		(net "GND")
	)
	(segment
		(start 131.27355 -125.758448)
		(end 130.66395 -125.758448)
		(width 0.3556)
		(layer "F.Cu")
		(net "GND")
	)
	(segment
		(start 383.185162 -281.05608)
		(end 383.185162 -281.59202)
		(width 0.254)
		(layer "F.Cu")
		(net "GND")
	)
	(segment
		(start 7.035546 -260.21665)
		(end 8.140446 -260.21665)
		(width 0.381)
		(layer "F.Cu")
		(net "GND")
	)
	(segment
		(start 7.035546 -240.666778)
		(end 8.140446 -240.666778)
		(width 0.381)
		(layer "F.Cu")
		(net "GND")
	)
	(segment
		(start 337.495134 -237.133892)
		(end 337.49488 -237.133638)
		(width 0.254)
		(layer "F.Cu")
		(net "GND")
	)
	(segment
		(start 27.328114 -305.266598)
		(end 28.433014 -305.266598)
		(width 0.381)
		(layer "F.Cu")
		(net "GND")
	)
	(segment
		(start 339.014562 -266.941808)
		(end 339.014562 -266.405868)
		(width 0.2032)
		(layer "F.Cu")
		(net "GND")
	)
	(segment
		(start 345.953334 -228.45903)
		(end 345.953334 -228.99497)
		(width 0.2032)
		(layer "F.Cu")
		(net "GND")
	)
	(segment
		(start 370.878862 -360.443272)
		(end 369.923822 -360.443272)
		(width 0.3556)
		(layer "F.Cu")
		(net "GND")
	)
	(segment
		(start 58.666888 -10.16508)
		(end 58.666888 -11.26998)
		(width 0.3556)
		(layer "F.Cu")
		(net "GND")
	)
	(segment
		(start 386.004562 -272.917158)
		(end 385.534662 -272.639282)
		(width 0.254)
		(layer "F.Cu")
		(net "GND")
	)
	(segment
		(start 122.558048 -265.592306)
		(end 122.558048 -266.127992)
		(width 0.254)
		(layer "F.Cu")
		(net "GND")
	)
	(segment
		(start 464.764882 -299.316648)
		(end 463.659982 -299.316648)
		(width 0.381)
		(layer "F.Cu")
		(net "GND")
	)
	(segment
		(start 276.373082 -266.1666)
		(end 275.268182 -266.1666)
		(width 0.381)
		(layer "F.Cu")
		(net "GND")
	)
	(segment
		(start 191.983614 -284.866588)
		(end 193.088514 -284.866588)
		(width 0.381)
		(layer "F.Cu")
		(net "GND")
	)
	(segment
		(start 339.400896 -57.45734)
		(end 338.90077 -57.605168)
		(width 0.254)
		(layer "F.Cu")
		(net "GND")
	)
	(segment
		(start 195.427346 -260.21665)
		(end 196.532246 -260.21665)
		(width 0.381)
		(layer "F.Cu")
		(net "GND")
	)
	(segment
		(start 63.726314 -235.566712)
		(end 65.047114 -235.566712)
		(width 0.381)
		(layer "F.Cu")
		(net "GND")
	)
	(segment
		(start 133.255512 -226.553268)
		(end 133.255512 -226.017582)
		(width 0.254)
		(layer "F.Cu")
		(net "GND")
	)
	(segment
		(start 38.315646 -199.01662)
		(end 37.210746 -199.01662)
		(width 0.381)
		(layer "F.Cu")
		(net "GND")
	)
	(segment
		(start 282.811982 -310.366664)
		(end 283.916882 -310.366664)
		(width 0.381)
		(layer "F.Cu")
		(net "GND")
	)
	(segment
		(start 311.882282 -277.216616)
		(end 312.987182 -277.216616)
		(width 0.381)
		(layer "F.Cu")
		(net "GND")
	)
	(segment
		(start 104.0384 -410.2608)
		(end 103.8098 -410.0322)
		(width 0.3556)
		(layer "F.Cu")
		(net "GND")
	)
	(segment
		(start 377.546362 -258.2672)
		(end 377.546362 -258.80314)
		(width 0.2032)
		(layer "F.Cu")
		(net "GND")
	)
	(segment
		(start 429.384714 -270.416782)
		(end 430.489614 -270.416782)
		(width 0.381)
		(layer "F.Cu")
		(net "GND")
	)
	(segment
		(start 99.422712 -246.08663)
		(end 99.422966 -246.086376)
		(width 0.2032)
		(layer "F.Cu")
		(net "GND")
	)
	(segment
		(start 305.443382 -310.366664)
		(end 306.548282 -310.366664)
		(width 0.381)
		(layer "F.Cu")
		(net "GND")
	)
	(segment
		(start 345.96959 -57.454546)
		(end 346.799662 -57.454546)
		(width 0.2032)
		(layer "F.Cu")
		(net "GND")
	)
	(segment
		(start 347.36278 -220.041978)
		(end 347.363034 -220.041724)
		(width 0.254)
		(layer "F.Cu")
		(net "GND")
	)
	(segment
		(start 214.615014 -272.966688)
		(end 215.719914 -272.966688)
		(width 0.381)
		(layer "F.Cu")
		(net "GND")
	)
	(segment
		(start 352.641662 -277.522178)
		(end 352.641662 -277.522432)
		(width 0.2032)
		(layer "F.Cu")
		(net "GND")
	)
	(segment
		(start 92.844366 -239.575086)
		(end 92.844366 -239.0394)
		(width 0.2032)
		(layer "F.Cu")
		(net "GND")
	)
	(segment
		(start 423.67962 -50.94732)
		(end 423.61866 -51.00828)
		(width 0.3556)
		(layer "F.Cu")
		(net "GND")
	)
	(segment
		(start 289.250882 -245.76659)
		(end 290.355782 -245.76659)
		(width 0.381)
		(layer "F.Cu")
		(net "GND")
	)
	(segment
		(start 433.484782 -200.716642)
		(end 434.589682 -200.716642)
		(width 0.381)
		(layer "F.Cu")
		(net "GND")
	)
	(segment
		(start 197.637146 -273.816572)
		(end 196.532246 -273.816572)
		(width 0.381)
		(layer "F.Cu")
		(net "GND")
	)
	(segment
		(start 444.472314 -270.416782)
		(end 443.367414 -270.416782)
		(width 0.381)
		(layer "F.Cu")
		(net "GND")
	)
	(segment
		(start 138.064494 -283.219144)
		(end 138.064748 -283.219398)
		(width 0.254)
		(layer "F.Cu")
		(net "GND")
	)
	(segment
		(start 98.123248 -261.244588)
		(end 98.122994 -261.244842)
		(width 0.2032)
		(layer "F.Cu")
		(net "GND")
	)
	(segment
		(start 53.403246 -313.766708)
		(end 54.724046 -313.766708)
		(width 0.381)
		(layer "F.Cu")
		(net "GND")
	)
	(segment
		(start 126.317248 -281.869896)
		(end 126.317248 -282.405836)
		(width 0.254)
		(layer "F.Cu")
		(net "GND")
	)
	(segment
		(start 355.461316 -285.6611)
		(end 355.461062 -285.661354)
		(width 0.254)
		(layer "F.Cu")
		(net "GND")
	)
	(segment
		(start 98.592894 -285.939484)
		(end 98.592894 -286.475424)
		(width 0.2032)
		(layer "F.Cu")
		(net "GND")
	)
	(segment
		(start 458.455014 -292.516814)
		(end 459.559914 -292.516814)
		(width 0.381)
		(layer "F.Cu")
		(net "GND")
	)
	(segment
		(start 351.702116 -275.35886)
		(end 351.702116 -275.894546)
		(width 0.2032)
		(layer "F.Cu")
		(net "GND")
	)
	(segment
		(start 133.365494 -281.591512)
		(end 133.365748 -281.591766)
		(width 0.254)
		(layer "F.Cu")
		(net "GND")
	)
	(segment
		(start 111.25708 -398.275048)
		(end 111.25708 -398.424908)
		(width 0.3556)
		(layer "F.Cu")
		(net "GND")
	)
	(segment
		(start 425.940982 -224.516696)
		(end 427.045882 -224.516696)
		(width 0.381)
		(layer "F.Cu")
		(net "GND")
	)
	(segment
		(start 132.425694 -282.683966)
		(end 132.425694 -283.219906)
		(width 0.254)
		(layer "F.Cu")
		(net "GND")
	)
	(segment
		(start 341.36838 -42.808906)
		(end 341.37727 -42.811446)
		(width 0.2032)
		(layer "F.Cu")
		(net "GND")
	)
	(segment
		(start 345.904058 -37.63518)
		(end 346.559378 -37.63518)
		(width 0.254)
		(layer "F.Cu")
		(net "GND")
	)
	(segment
		(start 338.434934 -225.739198)
		(end 338.434934 -225.203512)
		(width 0.2032)
		(layer "F.Cu")
		(net "GND")
	)
	(segment
		(start 11.135614 -275.516594)
		(end 12.240514 -275.516594)
		(width 0.381)
		(layer "F.Cu")
		(net "GND")
	)
	(segment
		(start 393.669774 -35.118802)
		(end 394.776706 -35.118802)
		(width 0.3556)
		(layer "F.Cu")
		(net "GND")
	)
	(segment
		(start 333.845662 -280.242264)
		(end 333.845662 -280.778204)
		(width 0.2032)
		(layer "F.Cu")
		(net "GND")
	)
	(segment
		(start 267.724382 -262.76681)
		(end 268.829282 -262.76681)
		(width 0.381)
		(layer "F.Cu")
		(net "GND")
	)
	(segment
		(start 261.285482 -210.066636)
		(end 260.180582 -210.066636)
		(width 0.381)
		(layer "F.Cu")
		(net "GND")
	)
	(segment
		(start 34.871914 -291.666676)
		(end 33.767014 -291.666676)
		(width 0.381)
		(layer "F.Cu")
		(net "GND")
	)
	(segment
		(start 307.782214 -236.416596)
		(end 308.887114 -236.416596)
		(width 0.381)
		(layer "F.Cu")
		(net "GND")
	)
	(segment
		(start 463.659982 -249.166634)
		(end 464.764882 -249.166634)
		(width 0.381)
		(layer "F.Cu")
		(net "GND")
	)
	(segment
		(start 371.437916 -267.219938)
		(end 371.437662 -267.755878)
		(width 0.254)
		(layer "F.Cu")
		(net "GND")
	)
	(segment
		(start 97.543112 -244.458744)
		(end 97.543366 -244.45849)
		(width 0.2032)
		(layer "F.Cu")
		(net "GND")
	)
	(segment
		(start 282.811982 -316.316614)
		(end 283.916882 -316.316614)
		(width 0.381)
		(layer "F.Cu")
		(net "GND")
	)
	(segment
		(start 211.619846 -279.766776)
		(end 212.724746 -279.766776)
		(width 0.381)
		(layer "F.Cu")
		(net "GND")
	)
	(segment
		(start 124.437648 -270.475456)
		(end 124.437394 -271.011396)
		(width 0.2032)
		(layer "F.Cu")
		(net "GND")
	)
	(segment
		(start 132.895848 -266.127992)
		(end 132.895594 -266.128246)
		(width 0.254)
		(layer "F.Cu")
		(net "GND")
	)
	(segment
		(start 44.754546 -285.716726)
		(end 45.859446 -285.716726)
		(width 0.381)
		(layer "F.Cu")
		(net "GND")
	)
	(segment
		(start 65.047114 -211.766658)
		(end 66.152014 -211.766658)
		(width 0.381)
		(layer "F.Cu")
		(net "GND")
	)
	(segment
		(start 378.956316 -283.497782)
		(end 378.956316 -284.033468)
		(width 0.254)
		(layer "F.Cu")
		(net "GND")
	)
	(segment
		(start 338.90458 -234.69219)
		(end 338.904834 -234.691936)
		(width 0.254)
		(layer "F.Cu")
		(net "GND")
	)
	(segment
		(start 49.755552 -164.222684)
		(end 49.755552 -164.864034)
		(width 0.381)
		(layer "F.Cu")
		(net "GND")
	)
	(segment
		(start 462.555082 -262.76681)
		(end 463.659982 -262.76681)
		(width 0.381)
		(layer "F.Cu")
		(net "GND")
	)
	(segment
		(start 74.10831 -39.070026)
		(end 74.816462 -39.070026)
		(width 0.2286)
		(layer "F.Cu")
		(net "GND")
	)
	(segment
		(start 44.754546 -240.666778)
		(end 45.859446 -240.666778)
		(width 0.381)
		(layer "F.Cu")
		(net "GND")
	)
	(segment
		(start 262.519414 -212.616796)
		(end 263.624314 -212.616796)
		(width 0.381)
		(layer "F.Cu")
		(net "GND")
	)
	(segment
		(start 23.228046 -268.71676)
		(end 24.332946 -268.71676)
		(width 0.381)
		(layer "F.Cu")
		(net "GND")
	)
	(segment
		(start 344.54338 -216.250774)
		(end 344.543634 -216.25052)
		(width 0.254)
		(layer "F.Cu")
		(net "GND")
	)
	(segment
		(start 260.180582 -308.666642)
		(end 259.075682 -308.666642)
		(width 0.381)
		(layer "F.Cu")
		(net "GND")
	)
	(segment
		(start 374.14708 -242.016788)
		(end 374.14708 -241.481102)
		(width 0.2032)
		(layer "F.Cu")
		(net "GND")
	)
	(segment
		(start 215.719914 -211.766658)
		(end 216.824814 -211.766658)
		(width 0.381)
		(layer "F.Cu")
		(net "GND")
	)
	(segment
		(start 28.638246 -390.294876)
		(end 28.028646 -390.294876)
		(width 0.3556)
		(layer "F.Cu")
		(net "GND")
	)
	(segment
		(start 179.105814 -271.266666)
		(end 178.000914 -271.266666)
		(width 0.381)
		(layer "F.Cu")
		(net "GND")
	)
	(segment
		(start 109.400594 -266.127992)
		(end 109.400848 -266.128246)
		(width 0.254)
		(layer "F.Cu")
		(net "GND")
	)
	(segment
		(start 158.813246 -285.716726)
		(end 157.599126 -285.716726)
		(width 0.381)
		(layer "F.Cu")
		(net "GND")
	)
	(segment
		(start 373.317516 -282.405582)
		(end 373.317262 -282.405836)
		(width 0.254)
		(layer "F.Cu")
		(net "GND")
	)
	(segment
		(start 56.398414 -194.766692)
		(end 57.503314 -194.766692)
		(width 0.381)
		(layer "F.Cu")
		(net "GND")
	)
	(segment
		(start 210.514946 -195.616576)
		(end 211.619846 -195.616576)
		(width 0.381)
		(layer "F.Cu")
		(net "GND")
	)
	(segment
		(start 184.439814 -233.86669)
		(end 185.544714 -233.86669)
		(width 0.381)
		(layer "F.Cu")
		(net "GND")
	)
	(segment
		(start 362.979716 -263.96442)
		(end 362.979716 -264.499852)
		(width 0.254)
		(layer "F.Cu")
		(net "GND")
	)
	(segment
		(start 130.076448 -287.288986)
		(end 130.076194 -287.28924)
		(width 0.254)
		(layer "F.Cu")
		(net "GND")
	)
	(segment
		(start 134.305294 -268.033754)
		(end 134.305548 -268.569694)
		(width 0.2032)
		(layer "F.Cu")
		(net "GND")
	)
	(segment
		(start 294.904414 -204.96657)
		(end 293.799514 -204.96657)
		(width 0.381)
		(layer "F.Cu")
		(net "GND")
	)
	(segment
		(start 208.176114 -200.716642)
		(end 209.281014 -200.716642)
		(width 0.381)
		(layer "F.Cu")
		(net "GND")
	)
	(segment
		(start 428.279814 -300.166786)
		(end 429.384714 -300.166786)
		(width 0.381)
		(layer "F.Cu")
		(net "GND")
	)
	(segment
		(start 276.373082 -215.166702)
		(end 275.268182 -215.166702)
		(width 0.381)
		(layer "F.Cu")
		(net "GND")
	)
	(segment
		(start 38.315646 -315.46673)
		(end 37.210746 -315.46673)
		(width 0.381)
		(layer "F.Cu")
		(net "GND")
	)
	(segment
		(start 366.738916 -285.125414)
		(end 366.738916 -285.661354)
		(width 0.254)
		(layer "F.Cu")
		(net "GND")
	)
	(segment
		(start 277.607014 -309.51678)
		(end 278.711914 -309.51678)
		(width 0.381)
		(layer "F.Cu")
		(net "GND")
	)
	(segment
		(start 8.140446 -248.31675)
		(end 9.245346 -248.31675)
		(width 0.381)
		(layer "F.Cu")
		(net "GND")
	)
	(segment
		(start 25.746964 -8.320024)
		(end 25.746964 -9.424924)
		(width 0.3556)
		(layer "F.Cu")
		(net "GND")
	)
	(segment
		(start 329.980036 -40.931846)
		(end 329.439778 -40.931846)
		(width 0.2032)
		(layer "F.Cu")
		(net "GND")
	)
	(segment
		(start 131.016248 -263.96442)
		(end 131.016248 -264.499852)
		(width 0.2032)
		(layer "F.Cu")
		(net "GND")
	)
	(segment
		(start 123.994926 -122.496834)
		(end 123.994926 -123.112784)
		(width 0.3556)
		(layer "F.Cu")
		(net "GND")
	)
	(segment
		(start 92.844112 -246.08663)
		(end 92.844112 -245.55069)
		(width 0.2032)
		(layer "F.Cu")
		(net "GND")
	)
	(segment
		(start 113.519712 -226.553268)
		(end 113.519712 -226.017582)
		(width 0.254)
		(layer "F.Cu")
		(net "GND")
	)
	(segment
		(start 12.240514 -233.86669)
		(end 13.345414 -233.86669)
		(width 0.381)
		(layer "F.Cu")
		(net "GND")
	)
	(segment
		(start 98.483166 -220.041724)
		(end 98.483166 -219.506038)
		(width 0.254)
		(layer "F.Cu")
		(net "GND")
	)
	(segment
		(start 441.028582 -238.116618)
		(end 442.133482 -238.116618)
		(width 0.381)
		(layer "F.Cu")
		(net "GND")
	)
	(segment
		(start 460.664814 -217.716608)
		(end 459.559914 -217.716608)
		(width 0.381)
		(layer "F.Cu")
		(net "GND")
	)
	(segment
		(start 113.629694 -272.917158)
		(end 113.629694 -273.453098)
		(width 0.254)
		(layer "F.Cu")
		(net "GND")
	)
	(segment
		(start 253.135892 -92.371164)
		(end 253.135892 -92.24137)
		(width 0.3556)
		(layer "F.Cu")
		(net "GND")
	)
	(segment
		(start 385.065016 -283.219398)
		(end 385.065016 -283.219906)
		(width 0.254)
		(layer "F.Cu")
		(net "GND")
	)
	(segment
		(start 443.367414 -281.466798)
		(end 444.472314 -281.466798)
		(width 0.381)
		(layer "F.Cu")
		(net "GND")
	)
	(segment
		(start 169.352214 -258.516628)
		(end 170.457114 -258.516628)
		(width 0.381)
		(layer "F.Cu")
		(net "GND")
	)
	(segment
		(start 335.725262 -268.84757)
		(end 335.725262 -269.38351)
		(width 0.2032)
		(layer "F.Cu")
		(net "GND")
	)
	(segment
		(start 364.537752 -393.988036)
		(end 364.92688 -393.598908)
		(width 0.3556)
		(layer "F.Cu")
		(net "GND")
	)
	(segment
		(start 336.195162 -279.428194)
		(end 336.195162 -279.964134)
		(width 0.2032)
		(layer "F.Cu")
		(net "GND")
	)
	(segment
		(start 132.315712 -223.297496)
		(end 132.315712 -222.76181)
		(width 0.254)
		(layer "F.Cu")
		(net "GND")
	)
	(segment
		(start 31.69793 -433.923948)
		(end 32.30753 -433.923948)
		(width 0.3556)
		(layer "F.Cu")
		(net "GND")
	)
	(segment
		(start 44.754546 -204.96657)
		(end 45.859446 -204.96657)
		(width 0.381)
		(layer "F.Cu")
		(net "GND")
	)
	(segment
		(start 99.422712 -228.1809)
		(end 99.422712 -227.64496)
		(width 0.2032)
		(layer "F.Cu")
		(net "GND")
	)
	(segment
		(start 26.662888 -416.666934)
		(end 27.131772 -416.666934)
		(width 0.3556)
		(layer "F.Cu")
		(net "GND")
	)
	(segment
		(start 409.748482 -204.116686)
		(end 410.853382 -204.116686)
		(width 0.381)
		(layer "F.Cu")
		(net "GND")
	)
	(segment
		(start 11.135614 -258.516628)
		(end 12.240514 -258.516628)
		(width 0.381)
		(layer "F.Cu")
		(net "GND")
	)
	(segment
		(start 405.648414 -290.816792)
		(end 406.753314 -290.816792)
		(width 0.381)
		(layer "F.Cu")
		(net "GND")
	)
	(segment
		(start 134.195566 -216.78646)
		(end 134.195566 -216.25052)
		(width 0.254)
		(layer "F.Cu")
		(net "GND")
	)
	(segment
		(start 102.5398 -102.215188)
		(end 102.5398 -102.118668)
		(width 0.3556)
		(layer "F.Cu")
		(net "GND")
	)
	(segment
		(start 260.180582 -310.366664)
		(end 259.075682 -310.366664)
		(width 0.381)
		(layer "F.Cu")
		(net "GND")
	)
	(segment
		(start 267.724382 -198.166736)
		(end 268.829282 -198.166736)
		(width 0.381)
		(layer "F.Cu")
		(net "GND")
	)
	(segment
		(start 96.713294 -281.05608)
		(end 96.713294 -281.591766)
		(width 0.254)
		(layer "F.Cu")
		(net "GND")
	)
	(segment
		(start 34.871914 -266.1666)
		(end 35.976814 -266.1666)
		(width 0.381)
		(layer "F.Cu")
		(net "GND")
	)
	(segment
		(start 267.724382 -221.116652)
		(end 268.829282 -221.116652)
		(width 0.381)
		(layer "F.Cu")
		(net "GND")
	)
	(segment
		(start 158.813246 -300.166786)
		(end 159.918146 -300.166786)
		(width 0.381)
		(layer "F.Cu")
		(net "GND")
	)
	(segment
		(start 355.930962 -272.917158)
		(end 355.930962 -273.452844)
		(width 0.2032)
		(layer "F.Cu")
		(net "GND")
	)
	(segment
		(start 191.983614 -295.916604)
		(end 193.088514 -295.916604)
		(width 0.381)
		(layer "F.Cu")
		(net "GND")
	)
	(segment
		(start 338.90458 -241.203226)
		(end 338.90458 -240.667286)
		(width 0.2032)
		(layer "F.Cu")
		(net "GND")
	)
	(segment
		(start 453.121014 -315.46673)
		(end 452.016114 -315.46673)
		(width 0.381)
		(layer "F.Cu")
		(net "GND")
	)
	(segment
		(start 449.677282 -308.666642)
		(end 448.572382 -308.666642)
		(width 0.381)
		(layer "F.Cu")
		(net "GND")
	)
	(segment
		(start 325.850758 -53.952902)
		(end 326.584818 -53.952902)
		(width 0.2032)
		(layer "F.Cu")
		(net "GND")
	)
	(segment
		(start 263.624314 -283.166566)
		(end 264.729214 -283.166566)
		(width 0.381)
		(layer "F.Cu")
		(net "GND")
	)
	(segment
		(start 312.987182 -249.166634)
		(end 314.092082 -249.166634)
		(width 0.381)
		(layer "F.Cu")
		(net "GND")
	)
	(segment
		(start 301.343314 -199.01662)
		(end 302.448214 -199.01662)
		(width 0.381)
		(layer "F.Cu")
		(net "GND")
	)
	(segment
		(start 18.679414 -310.366664)
		(end 19.784314 -310.366664)
		(width 0.381)
		(layer "F.Cu")
		(net "GND")
	)
	(segment
		(start 95.663512 -216.250774)
		(end 95.663766 -216.25052)
		(width 0.254)
		(layer "F.Cu")
		(net "GND")
	)
	(segment
		(start 19.784314 -284.866588)
		(end 20.889214 -284.866588)
		(width 0.381)
		(layer "F.Cu")
		(net "GND")
	)
	(segment
		(start 135.400034 -344.741754)
		(end 135.120888 -344.741754)
		(width 0.1778)
		(layer "F.Cu")
		(net "GND")
	)
	(segment
		(start 337.604862 -254.197612)
		(end 337.604862 -254.733552)
		(width 0.2032)
		(layer "F.Cu")
		(net "GND")
	)
	(segment
		(start 355.930962 -276.172676)
		(end 355.930962 -276.708362)
		(width 0.2032)
		(layer "F.Cu")
		(net "GND")
	)
	(segment
		(start 349.24238 -226.017582)
		(end 349.242634 -226.017328)
		(width 0.254)
		(layer "F.Cu")
		(net "GND")
	)
	(segment
		(start 8.140446 -244.916706)
		(end 9.245346 -244.916706)
		(width 0.381)
		(layer "F.Cu")
		(net "GND")
	)
	(segment
		(start 439.923682 -312.91657)
		(end 441.028582 -312.91657)
		(width 0.381)
		(layer "F.Cu")
		(net "GND")
	)
	(segment
		(start 91.544648 -273.730974)
		(end 91.544648 -274.266914)
		(width 0.2032)
		(layer "F.Cu")
		(net "GND")
	)
	(segment
		(start 122.558048 -264.499852)
		(end 122.557794 -264.500106)
		(width 0.2032)
		(layer "F.Cu")
		(net "GND")
	)
	(segment
		(start 210.514946 -260.21665)
		(end 211.619846 -260.21665)
		(width 0.381)
		(layer "F.Cu")
		(net "GND")
	)
	(segment
		(start 339.014562 -263.150604)
		(end 339.014562 -263.68629)
		(width 0.2032)
		(layer "F.Cu")
		(net "GND")
	)
	(segment
		(start 420.736014 -220.266768)
		(end 421.840914 -220.266768)
		(width 0.381)
		(layer "F.Cu")
		(net "GND")
	)
	(segment
		(start 334.205834 -217.87866)
		(end 334.20558 -217.878406)
		(width 0.2032)
		(layer "F.Cu")
		(net "GND")
	)
	(segment
		(start 27.328114 -306.96662)
		(end 28.433014 -306.96662)
		(width 0.381)
		(layer "F.Cu")
		(net "GND")
	)
	(segment
		(start 413.022796 -285.65856)
		(end 413.080962 -285.716726)
		(width 0.381)
		(layer "F.Cu")
		(net "GND")
	)
	(segment
		(start 410.853382 -213.46668)
		(end 411.958282 -213.46668)
		(width 0.381)
		(layer "F.Cu")
		(net "GND")
	)
	(segment
		(start 143.76908 -36.761928)
		(end 144.595342 -36.761928)
		(width 0.3556)
		(layer "F.Cu")
		(net "GND")
	)
	(segment
		(start 20.346924 -10.16508)
		(end 20.346924 -11.26998)
		(width 0.3556)
		(layer "F.Cu")
		(net "GND")
	)
	(segment
		(start 281.707082 -306.96662)
		(end 282.811982 -306.96662)
		(width 0.381)
		(layer "F.Cu")
		(net "GND")
	)
	(segment
		(start 56.398414 -196.466714)
		(end 57.503314 -196.466714)
		(width 0.381)
		(layer "F.Cu")
		(net "GND")
	)
	(segment
		(start 457.221082 -213.46668)
		(end 456.116182 -213.46668)
		(width 0.381)
		(layer "F.Cu")
		(net "GND")
	)
	(segment
		(start 345.593162 -279.96388)
		(end 345.593416 -279.964134)
		(width 0.254)
		(layer "F.Cu")
		(net "GND")
	)
	(segment
		(start 49.959514 -247.466612)
		(end 51.064414 -247.466612)
		(width 0.381)
		(layer "F.Cu")
		(net "GND")
	)
	(segment
		(start 208.176114 -221.116652)
		(end 209.281014 -221.116652)
		(width 0.381)
		(layer "F.Cu")
		(net "GND")
	)
	(segment
		(start 381.19558 -226.017582)
		(end 381.195834 -226.017328)
		(width 0.254)
		(layer "F.Cu")
		(net "GND")
	)
	(segment
		(start 424.166792 -11.26998)
		(end 424.166792 -10.16508)
		(width 0.3556)
		(layer "F.Cu")
		(net "GND")
	)
	(segment
		(start 34.871914 -226.216718)
		(end 35.976814 -226.216718)
		(width 0.381)
		(layer "F.Cu")
		(net "GND")
	)
	(segment
		(start 199.527414 -205.816708)
		(end 200.632314 -205.816708)
		(width 0.381)
		(layer "F.Cu")
		(net "GND")
	)
	(segment
		(start 91.074494 -257.175254)
		(end 91.074494 -256.639314)
		(width 0.2032)
		(layer "F.Cu")
		(net "GND")
	)
	(segment
		(start 96.133666 -243.644928)
		(end 96.133412 -243.644674)
		(width 0.2032)
		(layer "F.Cu")
		(net "GND")
	)
	(segment
		(start 15.684246 -278.066754)
		(end 16.789146 -278.066754)
		(width 0.381)
		(layer "F.Cu")
		(net "GND")
	)
	(segment
		(start 23.650702 -403.822408)
		(end 23.041102 -403.822408)
		(width 0.3556)
		(layer "F.Cu")
		(net "GND")
	)
	(segment
		(start 457.221082 -301.01667)
		(end 456.116182 -301.01667)
		(width 0.381)
		(layer "F.Cu")
		(net "GND")
	)
	(segment
		(start 130.906266 -217.600276)
		(end 130.906266 -217.064336)
		(width 0.254)
		(layer "F.Cu")
		(net "GND")
	)
	(segment
		(start 295.615106 -407.799794)
		(end 296.369994 -407.799794)
		(width 0.3556)
		(layer "F.Cu")
		(net "GND")
	)
	(segment
		(start 158.813246 -208.366614)
		(end 157.708346 -208.366614)
		(width 0.381)
		(layer "F.Cu")
		(net "GND")
	)
	(segment
		(start 193.088514 -277.216616)
		(end 194.193414 -277.216616)
		(width 0.381)
		(layer "F.Cu")
		(net "GND")
	)
	(segment
		(start 18.679414 -275.516594)
		(end 19.784314 -275.516594)
		(width 0.381)
		(layer "F.Cu")
		(net "GND")
	)
	(segment
		(start 45.859446 -270.416782)
		(end 46.964346 -270.416782)
		(width 0.381)
		(layer "F.Cu")
		(net "GND")
	)
	(segment
		(start 332.5114 -60.065158)
		(end 332.5114 -59.587638)
		(width 0.2032)
		(layer "F.Cu")
		(net "GND")
	)
	(segment
		(start 347.83014 -57.024016)
		(end 347.284294 -57.024016)
		(width 0.2032)
		(layer "F.Cu")
		(net "GND")
	)
	(segment
		(start 384.595116 -257.45313)
		(end 384.595116 -257.98907)
		(width 0.254)
		(layer "F.Cu")
		(net "GND")
	)
	(segment
		(start 271.168114 -279.766776)
		(end 270.063214 -279.766776)
		(width 0.381)
		(layer "F.Cu")
		(net "GND")
	)
	(segment
		(start 275.268182 -224.516696)
		(end 274.163282 -224.516696)
		(width 0.381)
		(layer "F.Cu")
		(net "GND")
	)
	(segment
		(start 123.027948 -282.68422)
		(end 123.027948 -283.219906)
		(width 0.254)
		(layer "F.Cu")
		(net "GND")
	)
	(segment
		(start 333.845662 -273.730974)
		(end 334.315816 -273.453098)
		(width 0.2032)
		(layer "F.Cu")
		(net "GND")
	)
	(segment
		(start 260.180582 -278.916638)
		(end 259.075682 -278.916638)
		(width 0.381)
		(layer "F.Cu")
		(net "GND")
	)
	(segment
		(start 211.619846 -234.716574)
		(end 212.724746 -234.716574)
		(width 0.381)
		(layer "F.Cu")
		(net "GND")
	)
	(segment
		(start 285.150814 -296.766742)
		(end 286.255714 -296.766742)
		(width 0.381)
		(layer "F.Cu")
		(net "GND")
	)
	(segment
		(start 435.823614 -272.116804)
		(end 436.928514 -272.116804)
		(width 0.381)
		(layer "F.Cu")
		(net "GND")
	)
	(segment
		(start 162.913314 -308.666642)
		(end 164.018214 -308.666642)
		(width 0.381)
		(layer "F.Cu")
		(net "GND")
	)
	(segment
		(start 377.906534 -240.389156)
		(end 377.90628 -240.388902)
		(width 0.2032)
		(layer "F.Cu")
		(net "GND")
	)
	(segment
		(start 428.279814 -309.51678)
		(end 429.384714 -309.51678)
		(width 0.381)
		(layer "F.Cu")
		(net "GND")
	)
	(segment
		(start 419.502082 -314.616592)
		(end 418.397182 -314.616592)
		(width 0.381)
		(layer "F.Cu")
		(net "GND")
	)
	(segment
		(start 134.195566 -247.714262)
		(end 134.195566 -247.178322)
		(width 0.2032)
		(layer "F.Cu")
		(net "GND")
	)
	(segment
		(start 169.075354 -310.366664)
		(end 170.457114 -310.366664)
		(width 0.381)
		(layer "F.Cu")
		(net "GND")
	)
	(segment
		(start 129.136648 -275.35886)
		(end 129.136648 -275.8948)
		(width 0.2032)
		(layer "F.Cu")
		(net "GND")
	)
	(segment
		(start 341.254334 -217.600276)
		(end 341.254334 -217.064336)
		(width 0.2032)
		(layer "F.Cu")
		(net "GND")
	)
	(segment
		(start 98.253296 -426.22978)
		(end 98.253296 -427.447964)
		(width 0.3556)
		(layer "F.Cu")
		(net "GND")
	)
	(segment
		(start 266.619482 -314.616592)
		(end 267.724382 -314.616592)
		(width 0.381)
		(layer "F.Cu")
		(net "GND")
	)
	(segment
		(start 409.748482 -221.116652)
		(end 410.853382 -221.116652)
		(width 0.381)
		(layer "F.Cu")
		(net "GND")
	)
	(segment
		(start 457.129896 -41.01211)
		(end 456.520296 -41.01211)
		(width 0.3556)
		(layer "F.Cu")
		(net "GND")
	)
	(segment
		(start 340.901782 -39.295324)
		(end 339.901276 -39.295324)
		(width 0.2032)
		(layer "F.Cu")
		(net "GND")
	)
	(segment
		(start 394.899896 -60.174886)
		(end 394.899896 -63.231776)
		(width 0.3556)
		(layer "F.Cu")
		(net "GND")
	)
	(segment
		(start 100.362512 -220.041978)
		(end 100.362766 -220.041724)
		(width 0.254)
		(layer "F.Cu")
		(net "GND")
	)
	(segment
		(start 166.357046 -296.766742)
		(end 165.252146 -296.766742)
		(width 0.381)
		(layer "F.Cu")
		(net "GND")
	)
	(segment
		(start 297.899582 -221.116652)
		(end 299.004482 -221.116652)
		(width 0.381)
		(layer "F.Cu")
		(net "GND")
	)
	(segment
		(start 345.554554 -49.950878)
		(end 345.15171 -49.59096)
		(width 0.1778)
		(layer "F.Cu")
		(net "GND")
	)
	(segment
		(start 44.754546 -248.31675)
		(end 45.859446 -248.31675)
		(width 0.381)
		(layer "F.Cu")
		(net "GND")
	)
	(segment
		(start 42.415714 -261.066788)
		(end 41.310814 -261.066788)
		(width 0.381)
		(layer "F.Cu")
		(net "GND")
	)
	(segment
		(start 112.110266 -238.761524)
		(end 112.110266 -238.225838)
		(width 0.254)
		(layer "F.Cu")
		(net "GND")
	)
	(segment
		(start 352.531934 -220.855794)
		(end 352.531934 -220.319854)
		(width 0.2032)
		(layer "F.Cu")
		(net "GND")
	)
	(segment
		(start 300.238414 -289.11677)
		(end 301.343314 -289.11677)
		(width 0.381)
		(layer "F.Cu")
		(net "GND")
	)
	(segment
		(start 125.737112 -246.08663)
		(end 125.737112 -245.55069)
		(width 0.2032)
		(layer "F.Cu")
		(net "GND")
	)
	(segment
		(start 372.377716 -256.361184)
		(end 372.377462 -256.361438)
		(width 0.254)
		(layer "F.Cu")
		(net "GND")
	)
	(segment
		(start 361.569762 -268.033754)
		(end 361.569762 -268.569694)
		(width 0.254)
		(layer "F.Cu")
		(net "GND")
	)
	(segment
		(start 121.508266 -224.111566)
		(end 121.508266 -223.575626)
		(width 0.2032)
		(layer "F.Cu")
		(net "GND")
	)
	(segment
		(start 460.664814 -246.616728)
		(end 459.559914 -246.616728)
		(width 0.381)
		(layer "F.Cu")
		(net "GND")
	)
	(segment
		(start 328.244962 -48.950372)
		(end 328.625708 -49.390046)
		(width 0.1778)
		(layer "F.Cu")
		(net "GND")
	)
	(segment
		(start 58.202322 -107.651296)
		(end 58.37555 -107.651296)
		(width 0.3556)
		(layer "F.Cu")
		(net "GND")
	)
	(segment
		(start 342.194134 -232.250488)
		(end 342.194134 -231.714548)
		(width 0.2032)
		(layer "F.Cu")
		(net "GND")
	)
	(segment
		(start 99.422712 -236.319822)
		(end 99.422966 -236.319568)
		(width 0.2032)
		(layer "F.Cu")
		(net "GND")
	)
	(segment
		(start 353.001834 -220.041724)
		(end 353.001834 -219.506038)
		(width 0.254)
		(layer "F.Cu")
		(net "GND")
	)
	(segment
		(start 84.856066 -242.017042)
		(end 84.385912 -242.294918)
		(width 0.254)
		(layer "F.Cu")
		(net "GND")
	)
	(segment
		(start 120.098566 -220.041724)
		(end 120.098566 -219.506038)
		(width 0.254)
		(layer "F.Cu")
		(net "GND")
	)
	(segment
		(start 311.882282 -261.066788)
		(end 312.987182 -261.066788)
		(width 0.381)
		(layer "F.Cu")
		(net "GND")
	)
	(segment
		(start 29.666946 -289.11677)
		(end 30.771846 -289.11677)
		(width 0.381)
		(layer "F.Cu")
		(net "GND")
	)
	(segment
		(start 277.607014 -292.516814)
		(end 278.711914 -292.516814)
		(width 0.381)
		(layer "F.Cu")
		(net "GND")
	)
	(segment
		(start 370.967762 -289.195002)
		(end 370.967762 -289.807142)
		(width 0.2032)
		(layer "F.Cu")
		(net "GND")
	)
	(segment
		(start 459.559914 -313.766708)
		(end 460.664814 -313.766708)
		(width 0.381)
		(layer "F.Cu")
		(net "GND")
	)
	(segment
		(start 18.88236 -168.509188)
		(end 19.12112 -168.509188)
		(width 0.3556)
		(layer "F.Cu")
		(net "GND")
	)
	(segment
		(start 439.923682 -314.616592)
		(end 441.028582 -314.616592)
		(width 0.381)
		(layer "F.Cu")
		(net "GND")
	)
	(segment
		(start 353.94138 -220.041978)
		(end 353.941634 -220.041724)
		(width 0.254)
		(layer "F.Cu")
		(net "GND")
	)
	(segment
		(start 27.328114 -204.116686)
		(end 28.433014 -204.116686)
		(width 0.381)
		(layer "F.Cu")
		(net "GND")
	)
	(segment
		(start 334.315562 -272.917158)
		(end 335.255362 -273.453098)
		(width 0.2032)
		(layer "F.Cu")
		(net "GND")
	)
	(segment
		(start 110.340648 -286.7533)
		(end 110.340648 -287.288986)
		(width 0.254)
		(layer "F.Cu")
		(net "GND")
	)
	(segment
		(start 26.223214 -205.816708)
		(end 27.328114 -205.816708)
		(width 0.381)
		(layer "F.Cu")
		(net "GND")
	)
	(segment
		(start 414.297114 -227.066602)
		(end 415.402014 -227.066602)
		(width 0.381)
		(layer "F.Cu")
		(net "GND")
	)
	(segment
		(start 420.7637 -174.519844)
		(end 420.548308 -174.735236)
		(width 0.381)
		(layer "F.Cu")
		(net "GND")
	)
	(segment
		(start 177.108104 -43.800014)
		(end 178.289204 -43.800014)
		(width 0.254)
		(layer "F.Cu")
		(net "GND")
	)
	(segment
		(start 348.412562 -282.683966)
		(end 348.412562 -283.219906)
		(width 0.254)
		(layer "F.Cu")
		(net "GND")
	)
	(segment
		(start 365.21898 -234.69219)
		(end 365.219234 -234.691936)
		(width 0.2032)
		(layer "F.Cu")
		(net "GND")
	)
	(segment
		(start 363.046518 -361.72775)
		(end 363.656118 -361.72775)
		(width 0.381)
		(layer "F.Cu")
		(net "GND")
	)
	(segment
		(start 15.684246 -295.06672)
		(end 16.789146 -295.06672)
		(width 0.381)
		(layer "F.Cu")
		(net "GND")
	)
	(segment
		(start 90.024712 -247.714262)
		(end 90.024712 -247.178322)
		(width 0.2032)
		(layer "F.Cu")
		(net "GND")
	)
	(segment
		(start 372.26748 -235.505752)
		(end 372.26748 -234.970066)
		(width 0.2032)
		(layer "F.Cu")
		(net "GND")
	)
	(segment
		(start 95.193866 -240.389156)
		(end 95.193612 -240.388902)
		(width 0.2032)
		(layer "F.Cu")
		(net "GND")
	)
	(segment
		(start 126.764542 -97.679002)
		(end 127.69596 -98.61042)
		(width 0.254)
		(layer "F.Cu")
		(net "GND")
	)
	(segment
		(start 137.130536 -273.453098)
		(end 137.124694 -273.453098)
		(width 0.254)
		(layer "F.Cu")
		(net "GND")
	)
	(segment
		(start 293.799514 -273.816572)
		(end 292.694614 -273.816572)
		(width 0.381)
		(layer "F.Cu")
		(net "GND")
	)
	(segment
		(start 463.659982 -224.516696)
		(end 464.764882 -224.516696)
		(width 0.381)
		(layer "F.Cu")
		(net "GND")
	)
	(segment
		(start 200.632314 -312.91657)
		(end 201.737214 -312.91657)
		(width 0.381)
		(layer "F.Cu")
		(net "GND")
	)
	(segment
		(start 144.295368 -114.73434)
		(end 144.97304 -114.73434)
		(width 0.3556)
		(layer "F.Cu")
		(net "GND")
	)
	(segment
		(start 424.836082 -202.416664)
		(end 425.940982 -202.416664)
		(width 0.381)
		(layer "F.Cu")
		(net "GND")
	)
	(segment
		(start 296.794682 -226.216718)
		(end 297.899582 -226.216718)
		(width 0.381)
		(layer "F.Cu")
		(net "GND")
	)
	(segment
		(start 175.005746 -216.016586)
		(end 173.900846 -216.016586)
		(width 0.381)
		(layer "F.Cu")
		(net "GND")
	)
	(segment
		(start 282.811982 -216.866724)
		(end 283.916882 -216.866724)
		(width 0.381)
		(layer "F.Cu")
		(net "GND")
	)
	(segment
		(start 311.882282 -215.166702)
		(end 312.987182 -215.166702)
		(width 0.381)
		(layer "F.Cu")
		(net "GND")
	)
	(segment
		(start 302.600614 -423.13479)
		(end 302.575214 -423.16019)
		(width 0.3556)
		(layer "F.Cu")
		(net "GND")
	)
	(segment
		(start 39.420546 -276.366732)
		(end 38.315646 -276.366732)
		(width 0.381)
		(layer "F.Cu")
		(net "GND")
	)
	(segment
		(start 270.063214 -283.166566)
		(end 271.168114 -283.166566)
		(width 0.381)
		(layer "F.Cu")
		(net "GND")
	)
	(segment
		(start 260.180582 -194.766692)
		(end 259.075682 -194.766692)
		(width 0.381)
		(layer "F.Cu")
		(net "GND")
	)
	(segment
		(start 138.064494 -269.66164)
		(end 138.81989 -269.66164)
		(width 0.254)
		(layer "F.Cu")
		(net "GND")
	)
	(segment
		(start 191.983614 -269.566644)
		(end 193.088514 -269.566644)
		(width 0.381)
		(layer "F.Cu")
		(net "GND")
	)
	(segment
		(start 300.238414 -268.71676)
		(end 301.343314 -268.71676)
		(width 0.381)
		(layer "F.Cu")
		(net "GND")
	)
	(segment
		(start 377.906534 -230.622602)
		(end 377.90628 -230.622348)
		(width 0.2032)
		(layer "F.Cu")
		(net "GND")
	)
	(segment
		(start 297.899582 -211.766658)
		(end 299.004482 -211.766658)
		(width 0.381)
		(layer "F.Cu")
		(net "GND")
	)
	(segment
		(start 132.785612 -232.250234)
		(end 132.785612 -231.714548)
		(width 0.2032)
		(layer "F.Cu")
		(net "GND")
	)
	(segment
		(start 456.116182 -230.466646)
		(end 455.011282 -230.466646)
		(width 0.381)
		(layer "F.Cu")
		(net "GND")
	)
	(segment
		(start 263.624314 -276.366732)
		(end 264.729214 -276.366732)
		(width 0.381)
		(layer "F.Cu")
		(net "GND")
	)
	(segment
		(start 196.532246 -267.016738)
		(end 197.637146 -267.016738)
		(width 0.381)
		(layer "F.Cu")
		(net "GND")
	)
	(segment
		(start 330.252578 -48.920146)
		(end 329.980798 -48.450246)
		(width 0.254)
		(layer "F.Cu")
		(net "GND")
	)
	(segment
		(start 157.708346 -199.01662)
		(end 158.813246 -199.01662)
		(width 0.381)
		(layer "F.Cu")
		(net "GND")
	)
	(segment
		(start 364.27918 -226.553268)
		(end 364.27918 -226.017582)
		(width 0.254)
		(layer "F.Cu")
		(net "GND")
	)
	(segment
		(start 270.063214 -317.166752)
		(end 271.168114 -317.166752)
		(width 0.381)
		(layer "F.Cu")
		(net "GND")
	)
	(segment
		(start 193.78041 -124.170948)
		(end 194.39001 -124.170948)
		(width 0.3556)
		(layer "F.Cu")
		(net "GND")
	)
	(segment
		(start 421.840914 -270.416782)
		(end 422.945814 -270.416782)
		(width 0.381)
		(layer "F.Cu")
		(net "GND")
	)
	(segment
		(start 280.271474 -424.94835)
		(end 280.14422 -424.821096)
		(width 0.3556)
		(layer "F.Cu")
		(net "GND")
	)
	(segment
		(start 88.255094 -266.405868)
		(end 88.255094 -266.941808)
		(width 0.2032)
		(layer "F.Cu")
		(net "GND")
	)
	(segment
		(start 337.96478 -247.714262)
		(end 337.96478 -247.178322)
		(width 0.2032)
		(layer "F.Cu")
		(net "GND")
	)
	(segment
		(start 349.352362 -261.522718)
		(end 349.352362 -262.058404)
		(width 0.254)
		(layer "F.Cu")
		(net "GND")
	)
	(segment
		(start 125.737112 -231.436418)
		(end 125.737366 -231.436164)
		(width 0.2032)
		(layer "F.Cu")
		(net "GND")
	)
	(segment
		(start 134.305294 -263.150604)
		(end 134.305294 -263.68629)
		(width 0.2032)
		(layer "F.Cu")
		(net "GND")
	)
	(segment
		(start 14.579346 -246.616728)
		(end 15.684246 -246.616728)
		(width 0.381)
		(layer "F.Cu")
		(net "GND")
	)
	(segment
		(start 130.906266 -242.017042)
		(end 130.906012 -242.016788)
		(width 0.2032)
		(layer "F.Cu")
		(net "GND")
	)
	(segment
		(start 342.824816 -37.08273)
		(end 342.90254 -37.160454)
		(width 0.2032)
		(layer "F.Cu")
		(net "GND")
	)
	(segment
		(start 158.813246 -317.166752)
		(end 157.708346 -317.166752)
		(width 0.381)
		(layer "F.Cu")
		(net "GND")
	)
	(segment
		(start 49.959514 -269.566644)
		(end 51.064414 -269.566644)
		(width 0.381)
		(layer "F.Cu")
		(net "GND")
	)
	(segment
		(start 15.684246 -214.316564)
		(end 16.789146 -214.316564)
		(width 0.381)
		(layer "F.Cu")
		(net "GND")
	)
	(segment
		(start 410.853382 -314.616592)
		(end 409.748482 -314.616592)
		(width 0.381)
		(layer "F.Cu")
		(net "GND")
	)
	(segment
		(start 137.014712 -247.714262)
		(end 137.014966 -247.714008)
		(width 0.2032)
		(layer "F.Cu")
		(net "GND")
	)
	(segment
		(start 372.26748 -238.76127)
		(end 372.26748 -238.225584)
		(width 0.2032)
		(layer "F.Cu")
		(net "GND")
	)
	(segment
		(start 419.502082 -305.266598)
		(end 418.397182 -305.266598)
		(width 0.381)
		(layer "F.Cu")
		(net "GND")
	)
	(segment
		(start 328.895964 -57.605168)
		(end 329.89647 -57.605168)
		(width 0.2032)
		(layer "F.Cu")
		(net "GND")
	)
	(segment
		(start 267.724382 -289.966654)
		(end 268.829282 -289.966654)
		(width 0.381)
		(layer "F.Cu")
		(net "GND")
	)
	(segment
		(start 421.840914 -195.616576)
		(end 422.945814 -195.616576)
		(width 0.381)
		(layer "F.Cu")
		(net "GND")
	)
	(segment
		(start 293.799514 -203.266802)
		(end 292.694614 -203.266802)
		(width 0.381)
		(layer "F.Cu")
		(net "GND")
	)
	(segment
		(start 120.098312 -226.553268)
		(end 120.098312 -226.017582)
		(width 0.254)
		(layer "F.Cu")
		(net "GND")
	)
	(segment
		(start 84.626196 -96.642428)
		(end 83.925918 -96.642428)
		(width 0.3556)
		(layer "F.Cu")
		(net "GND")
	)
	(segment
		(start 97.543366 -220.041724)
		(end 97.543366 -219.506038)
		(width 0.254)
		(layer "F.Cu")
		(net "GND")
	)
	(segment
		(start 134.665466 -224.111566)
		(end 134.665466 -223.575626)
		(width 0.2032)
		(layer "F.Cu")
		(net "GND")
	)
	(segment
		(start 111.640112 -219.506292)
		(end 111.640366 -219.506038)
		(width 0.254)
		(layer "F.Cu")
		(net "GND")
	)
	(segment
		(start 311.882282 -239.81664)
		(end 312.987182 -239.81664)
		(width 0.381)
		(layer "F.Cu")
		(net "GND")
	)
	(segment
		(start 207.70215 -114.0968)
		(end 207.70215 -114.53495)
		(width 0.3556)
		(layer "F.Cu")
		(net "GND")
	)
	(segment
		(start 198.54164 -95.16491)
		(end 197.23989 -95.16491)
		(width 0.3556)
		(layer "F.Cu")
		(net "GND")
	)
	(segment
		(start 361.45978 -248.806462)
		(end 361.460034 -248.806208)
		(width 0.254)
		(layer "F.Cu")
		(net "GND")
	)
	(segment
		(start 347.363034 -233.06405)
		(end 347.363034 -232.528364)
		(width 0.254)
		(layer "F.Cu")
		(net "GND")
	)
	(segment
		(start 272.273014 -248.31675)
		(end 271.168114 -248.31675)
		(width 0.381)
		(layer "F.Cu")
		(net "GND")
	)
	(segment
		(start 336.085434 -220.041978)
		(end 336.085434 -219.506038)
		(width 0.254)
		(layer "F.Cu")
		(net "GND")
	)
	(segment
		(start 38.315646 -313.766708)
		(end 37.210746 -313.766708)
		(width 0.381)
		(layer "F.Cu")
		(net "GND")
	)
	(segment
		(start 46.750478 -102.888034)
		(end 47.360078 -102.888034)
		(width 0.3556)
		(layer "F.Cu")
		(net "GND")
	)
	(segment
		(start 96.603312 -223.297496)
		(end 96.603312 -222.76181)
		(width 0.254)
		(layer "F.Cu")
		(net "GND")
	)
	(segment
		(start 340.784434 -231.436164)
		(end 340.784434 -230.900478)
		(width 0.2032)
		(layer "F.Cu")
		(net "GND")
	)
	(segment
		(start 122.558048 -263.96442)
		(end 122.558048 -264.499852)
		(width 0.2032)
		(layer "F.Cu")
		(net "GND")
	)
	(segment
		(start 61.53277 -40.681148)
		(end 61.53277 -41.278048)
		(width 0.3556)
		(layer "F.Cu")
		(net "GND")
	)
	(segment
		(start 136.545066 -245.27256)
		(end 136.075166 -245.55069)
		(width 0.254)
		(layer "F.Cu")
		(net "GND")
	)
	(segment
		(start 202.971146 -296.766742)
		(end 204.076046 -296.766742)
		(width 0.381)
		(layer "F.Cu")
		(net "GND")
	)
	(segment
		(start 333.735934 -217.06459)
		(end 333.73568 -217.064336)
		(width 0.2032)
		(layer "F.Cu")
		(net "GND")
	)
	(segment
		(start 45.859446 -267.016738)
		(end 46.964346 -267.016738)
		(width 0.381)
		(layer "F.Cu")
		(net "GND")
	)
	(segment
		(start 374.257316 -270.475456)
		(end 374.257062 -271.011396)
		(width 0.2032)
		(layer "F.Cu")
		(net "GND")
	)
	(segment
		(start 335.615534 -246.900446)
		(end 335.615534 -246.364506)
		(width 0.2032)
		(layer "F.Cu")
		(net "GND")
	)
	(segment
		(start 386.364734 -240.389156)
		(end 385.894834 -240.667286)
		(width 0.254)
		(layer "F.Cu")
		(net "GND")
	)
	(segment
		(start 98.123248 -284.033468)
		(end 98.122994 -284.033722)
		(width 0.254)
		(layer "F.Cu")
		(net "GND")
	)
	(segment
		(start 184.439814 -213.46668)
		(end 185.544714 -213.46668)
		(width 0.381)
		(layer "F.Cu")
		(net "GND")
	)
	(segment
		(start 99.532694 -258.802886)
		(end 99.532948 -258.80314)
		(width 0.2032)
		(layer "F.Cu")
		(net "GND")
	)
	(segment
		(start 338.93506 -54.558946)
		(end 338.394548 -54.558946)
		(width 0.2032)
		(layer "F.Cu")
		(net "GND")
	)
	(segment
		(start 415.643822 -46.171612)
		(end 415.978594 -45.83684)
		(width 0.3556)
		(layer "F.Cu")
		(net "GND")
	)
	(segment
		(start 435.823614 -231.316784)
		(end 436.928514 -231.316784)
		(width 0.381)
		(layer "F.Cu")
		(net "GND")
	)
	(segment
		(start 204.076046 -221.96679)
		(end 205.180946 -221.96679)
		(width 0.381)
		(layer "F.Cu")
		(net "GND")
	)
	(segment
		(start 385.56946 -287.381696)
		(end 385.534916 -287.41624)
		(width 0.254)
		(layer "F.Cu")
		(net "GND")
	)
	(segment
		(start 122.917712 -220.041978)
		(end 122.917966 -220.041724)
		(width 0.254)
		(layer "F.Cu")
		(net "GND")
	)
	(segment
		(start 170.457114 -272.966688)
		(end 171.790614 -272.966688)
		(width 0.381)
		(layer "F.Cu")
		(net "GND")
	)
	(segment
		(start 365.21898 -216.78646)
		(end 365.21898 -216.250774)
		(width 0.254)
		(layer "F.Cu")
		(net "GND")
	)
	(segment
		(start 272.273014 -206.666592)
		(end 271.168114 -206.666592)
		(width 0.381)
		(layer "F.Cu")
		(net "GND")
	)
	(segment
		(start 267.724382 -207.51673)
		(end 268.829282 -207.51673)
		(width 0.381)
		(layer "F.Cu")
		(net "GND")
	)
	(segment
		(start 18.679414 -239.81664)
		(end 19.784314 -239.81664)
		(width 0.381)
		(layer "F.Cu")
		(net "GND")
	)
	(segment
		(start 173.900846 -244.916706)
		(end 172.795946 -244.916706)
		(width 0.381)
		(layer "F.Cu")
		(net "GND")
	)
	(segment
		(start 124.437394 -264.500106)
		(end 124.437394 -264.50036)
		(width 0.2032)
		(layer "F.Cu")
		(net "GND")
	)
	(segment
		(start 137.594594 -254.197612)
		(end 137.154158 -253.943104)
		(width 0.2032)
		(layer "F.Cu")
		(net "GND")
	)
	(segment
		(start 380.835916 -263.96442)
		(end 380.835916 -264.50036)
		(width 0.2032)
		(layer "F.Cu")
		(net "GND")
	)
	(segment
		(start 214.615014 -291.666676)
		(end 215.719914 -291.666676)
		(width 0.381)
		(layer "F.Cu")
		(net "GND")
	)
	(segment
		(start 177.108104 -48.299878)
		(end 178.289204 -48.299878)
		(width 0.254)
		(layer "F.Cu")
		(net "GND")
	)
	(segment
		(start 207.071214 -226.216718)
		(end 208.176114 -226.216718)
		(width 0.381)
		(layer "F.Cu")
		(net "GND")
	)
	(segment
		(start 382.245362 -287.567116)
		(end 382.245362 -288.102802)
		(width 0.254)
		(layer "F.Cu")
		(net "GND")
	)
	(segment
		(start 462.555082 -250.866656)
		(end 463.659982 -250.866656)
		(width 0.381)
		(layer "F.Cu")
		(net "GND")
	)
	(segment
		(start 307.782214 -233.016806)
		(end 308.887114 -233.016806)
		(width 0.381)
		(layer "F.Cu")
		(net "GND")
	)
	(segment
		(start 348.772734 -224.111566)
		(end 348.772734 -223.575626)
		(width 0.2032)
		(layer "F.Cu")
		(net "GND")
	)
	(segment
		(start 123.497848 -267.219938)
		(end 123.497594 -267.755878)
		(width 0.254)
		(layer "F.Cu")
		(net "GND")
	)
	(segment
		(start 88.615266 -230.622602)
		(end 88.615012 -230.622348)
		(width 0.2032)
		(layer "F.Cu")
		(net "GND")
	)
	(segment
		(start 53.403246 -214.316564)
		(end 52.298346 -214.316564)
		(width 0.381)
		(layer "F.Cu")
		(net "GND")
	)
	(segment
		(start 207.071214 -262.76681)
		(end 208.176114 -262.76681)
		(width 0.381)
		(layer "F.Cu")
		(net "GND")
	)
	(segment
		(start 89.664794 -267.219938)
		(end 89.664794 -267.755878)
		(width 0.2032)
		(layer "F.Cu")
		(net "GND")
	)
	(segment
		(start 296.794682 -247.466612)
		(end 297.899582 -247.466612)
		(width 0.381)
		(layer "F.Cu")
		(net "GND")
	)
	(segment
		(start 285.150814 -270.416782)
		(end 286.255714 -270.416782)
		(width 0.381)
		(layer "F.Cu")
		(net "GND")
	)
	(segment
		(start 312.987182 -306.96662)
		(end 314.092082 -306.96662)
		(width 0.381)
		(layer "F.Cu")
		(net "GND")
	)
	(segment
		(start 448.572382 -310.366664)
		(end 447.467482 -310.366664)
		(width 0.381)
		(layer "F.Cu")
		(net "GND")
	)
	(segment
		(start 188.988446 -307.816758)
		(end 190.093346 -307.816758)
		(width 0.381)
		(layer "F.Cu")
		(net "GND")
	)
	(segment
		(start 44.754546 -265.316716)
		(end 45.859446 -265.316716)
		(width 0.381)
		(layer "F.Cu")
		(net "GND")
	)
	(segment
		(start 460.664814 -216.016586)
		(end 459.559914 -216.016586)
		(width 0.381)
		(layer "F.Cu")
		(net "GND")
	)
	(segment
		(start 99.422966 -220.041724)
		(end 99.422966 -219.506038)
		(width 0.254)
		(layer "F.Cu")
		(net "GND")
	)
	(segment
		(start 131.016248 -255.825498)
		(end 131.016248 -256.361184)
		(width 0.254)
		(layer "F.Cu")
		(net "GND")
	)
	(segment
		(start 49.959514 -310.366664)
		(end 51.064414 -310.366664)
		(width 0.381)
		(layer "F.Cu")
		(net "GND")
	)
	(segment
		(start 110.230666 -244.737128)
		(end 110.23092 -244.736874)
		(width 0.254)
		(layer "F.Cu")
		(net "GND")
	)
	(segment
		(start 460.664814 -221.96679)
		(end 459.559914 -221.96679)
		(width 0.381)
		(layer "F.Cu")
		(net "GND")
	)
	(segment
		(start 294.904414 -223.666558)
		(end 293.799514 -223.666558)
		(width 0.381)
		(layer "F.Cu")
		(net "GND")
	)
	(segment
		(start 425.940982 -264.466578)
		(end 427.045882 -264.466578)
		(width 0.381)
		(layer "F.Cu")
		(net "GND")
	)
	(segment
		(start 378.846334 -233.87812)
		(end 378.84608 -233.877866)
		(width 0.2032)
		(layer "F.Cu")
		(net "GND")
	)
	(segment
		(start 428.279814 -298.466764)
		(end 429.384714 -298.466764)
		(width 0.381)
		(layer "F.Cu")
		(net "GND")
	)
	(segment
		(start 179.105814 -216.866724)
		(end 178.000914 -216.866724)
		(width 0.381)
		(layer "F.Cu")
		(net "GND")
	)
	(segment
		(start 364.27918 -216.78646)
		(end 364.27918 -216.250774)
		(width 0.254)
		(layer "F.Cu")
		(net "GND")
	)
	(segment
		(start 96.713294 -285.939484)
		(end 96.713294 -286.475424)
		(width 0.2032)
		(layer "F.Cu")
		(net "GND")
	)
	(segment
		(start 220.487494 -99.21748)
		(end 221.1578 -99.21748)
		(width 0.3556)
		(layer "F.Cu")
		(net "GND")
	)
	(segment
		(start 26.223214 -213.46668)
		(end 27.328114 -213.46668)
		(width 0.381)
		(layer "F.Cu")
		(net "GND")
	)
	(segment
		(start 185.544714 -210.066636)
		(end 186.649614 -210.066636)
		(width 0.381)
		(layer "F.Cu")
		(net "GND")
	)
	(segment
		(start 348.882462 -268.847824)
		(end 348.882462 -269.38351)
		(width 0.2032)
		(layer "F.Cu")
		(net "GND")
	)
	(segment
		(start 424.836082 -216.866724)
		(end 425.940982 -216.866724)
		(width 0.381)
		(layer "F.Cu")
		(net "GND")
	)
	(segment
		(start 155.14828 -120.106948)
		(end 154.992324 -119.950992)
		(width 0.3556)
		(layer "F.Cu")
		(net "GND")
	)
	(segment
		(start 282.811982 -238.116618)
		(end 283.916882 -238.116618)
		(width 0.381)
		(layer "F.Cu")
		(net "GND")
	)
	(segment
		(start 101.412294 -272.917158)
		(end 101.412294 -273.453098)
		(width 0.2032)
		(layer "F.Cu")
		(net "GND")
	)
	(segment
		(start 457.221082 -239.81664)
		(end 456.116182 -239.81664)
		(width 0.381)
		(layer "F.Cu")
		(net "GND")
	)
	(segment
		(start 307.782214 -270.416782)
		(end 308.887114 -270.416782)
		(width 0.381)
		(layer "F.Cu")
		(net "GND")
	)
	(segment
		(start 300.022514 -273.816572)
		(end 301.343314 -273.816572)
		(width 0.381)
		(layer "F.Cu")
		(net "GND")
	)
	(segment
		(start 363.33938 -226.553268)
		(end 363.33938 -226.017582)
		(width 0.254)
		(layer "F.Cu")
		(net "GND")
	)
	(segment
		(start 308.887114 -290.816792)
		(end 309.992014 -290.816792)
		(width 0.381)
		(layer "F.Cu")
		(net "GND")
	)
	(segment
		(start 335.14538 -237.411768)
		(end 335.14538 -237.947454)
		(width 0.254)
		(layer "F.Cu")
		(net "GND")
	)
	(segment
		(start 45.859446 -283.166566)
		(end 46.964346 -283.166566)
		(width 0.381)
		(layer "F.Cu")
		(net "GND")
	)
	(segment
		(start 328.244962 -45.949108)
		(end 328.625708 -46.570646)
		(width 0.1778)
		(layer "F.Cu")
		(net "GND")
	)
	(segment
		(start 368.148362 -282.683966)
		(end 368.148616 -282.68422)
		(width 0.254)
		(layer "F.Cu")
		(net "GND")
	)
	(segment
		(start 289.250882 -205.816708)
		(end 290.355782 -205.816708)
		(width 0.381)
		(layer "F.Cu")
		(net "GND")
	)
	(segment
		(start 59.842146 -246.616728)
		(end 60.947046 -246.616728)
		(width 0.381)
		(layer "F.Cu")
		(net "GND")
	)
	(segment
		(start 376.96648 -243.644674)
		(end 376.96648 -243.108988)
		(width 0.2032)
		(layer "F.Cu")
		(net "GND")
	)
	(segment
		(start 308.108604 -13.68044)
		(end 308.108604 -14.412468)
		(width 0.3556)
		(layer "F.Cu")
		(net "GND")
	)
	(segment
		(start 187.883546 -313.766708)
		(end 188.988446 -313.766708)
		(width 0.381)
		(layer "F.Cu")
		(net "GND")
	)
	(segment
		(start 299.890434 -423.56532)
		(end 300.279562 -423.954448)
		(width 0.3556)
		(layer "F.Cu")
		(net "GND")
	)
	(segment
		(start 77.227938 -347.61551)
		(end 77.493876 -347.881448)
		(width 0.381)
		(layer "F.Cu")
		(net "GND")
	)
	(segment
		(start 81.618582 -37.743892)
		(end 82.482182 -37.743892)
		(width 0.3556)
		(layer "F.Cu")
		(net "GND")
	)
	(segment
		(start 383.185162 -282.683966)
		(end 383.185162 -283.219906)
		(width 0.254)
		(layer "F.Cu")
		(net "GND")
	)
	(segment
		(start 34.871914 -275.516594)
		(end 33.767014 -275.516594)
		(width 0.381)
		(layer "F.Cu")
		(net "GND")
	)
	(segment
		(start 370.027962 -274.54479)
		(end 370.028216 -275.08073)
		(width 0.2032)
		(layer "F.Cu")
		(net "GND")
	)
	(segment
		(start 126.317248 -275.35886)
		(end 126.316994 -275.8948)
		(width 0.2032)
		(layer "F.Cu")
		(net "GND")
	)
	(segment
		(start 120.208294 -287.567116)
		(end 120.208294 -288.103056)
		(width 0.254)
		(layer "F.Cu")
		(net "GND")
	)
	(segment
		(start 312.987182 -216.866724)
		(end 314.307982 -216.866724)
		(width 0.381)
		(layer "F.Cu")
		(net "GND")
	)
	(segment
		(start 420.35222 -344.017346)
		(end 421.292528 -344.017346)
		(width 0.508)
		(layer "F.Cu")
		(net "GND")
	)
	(segment
		(start 337.495134 -220.855794)
		(end 337.495134 -220.319854)
		(width 0.2032)
		(layer "F.Cu")
		(net "GND")
	)
	(segment
		(start 304.122582 -314.616592)
		(end 305.443382 -314.616592)
		(width 0.381)
		(layer "F.Cu")
		(net "GND")
	)
	(segment
		(start 338.90077 -59.265312)
		(end 338.787994 -58.813192)
		(width 0.2032)
		(layer "F.Cu")
		(net "GND")
	)
	(segment
		(start 135.245094 -275.08073)
		(end 135.245348 -275.080984)
		(width 0.2032)
		(layer "F.Cu")
		(net "GND")
	)
	(segment
		(start 181.444646 -250.016772)
		(end 182.549546 -250.016772)
		(width 0.381)
		(layer "F.Cu")
		(net "GND")
	)
	(segment
		(start 88.145366 -220.041978)
		(end 88.145366 -219.506038)
		(width 0.254)
		(layer "F.Cu")
		(net "GND")
	)
	(segment
		(start 345.48318 -249.342148)
		(end 345.483434 -249.341894)
		(width 0.2032)
		(layer "F.Cu")
		(net "GND")
	)
	(segment
		(start 376.49658 -222.76181)
		(end 376.496834 -222.761556)
		(width 0.254)
		(layer "F.Cu")
		(net "GND")
	)
	(segment
		(start 379.896116 -286.7533)
		(end 379.896116 -287.288986)
		(width 0.254)
		(layer "F.Cu")
		(net "GND")
	)
	(segment
		(start 106.941112 -223.297496)
		(end 106.941112 -222.76181)
		(width 0.254)
		(layer "F.Cu")
		(net "GND")
	)
	(segment
		(start 86.265766 -223.297496)
		(end 86.265766 -222.761556)
		(width 0.2032)
		(layer "F.Cu")
		(net "GND")
	)
	(segment
		(start 463.659982 -205.816708)
		(end 464.764882 -205.816708)
		(width 0.381)
		(layer "F.Cu")
		(net "GND")
	)
	(segment
		(start 59.842146 -214.316564)
		(end 60.947046 -214.316564)
		(width 0.381)
		(layer "F.Cu")
		(net "GND")
	)
	(segment
		(start 139.062206 -248.528078)
		(end 139.214606 -248.680478)
		(width 0.2032)
		(layer "F.Cu")
		(net "GND")
	)
	(segment
		(start 89.664794 -277.522432)
		(end 89.664794 -276.986492)
		(width 0.2032)
		(layer "F.Cu")
		(net "GND")
	)
	(segment
		(start 137.124694 -255.011682)
		(end 136.184894 -255.547622)
		(width 0.254)
		(layer "F.Cu")
		(net "GND")
	)
	(segment
		(start 409.58262 -312.91657)
		(end 410.853382 -312.91657)
		(width 0.381)
		(layer "F.Cu")
		(net "GND")
	)
	(segment
		(start 210.514946 -248.31675)
		(end 211.619846 -248.31675)
		(width 0.381)
		(layer "F.Cu")
		(net "GND")
	)
	(segment
		(start 166.357046 -311.216802)
		(end 167.65778 -311.216802)
		(width 0.381)
		(layer "F.Cu")
		(net "GND")
	)
	(segment
		(start 349.822516 -254.197612)
		(end 349.822516 -254.733044)
		(width 0.2032)
		(layer "F.Cu")
		(net "GND")
	)
	(segment
		(start 418.397182 -204.116686)
		(end 417.292282 -204.116686)
		(width 0.381)
		(layer "F.Cu")
		(net "GND")
	)
	(segment
		(start 86.845648 -276.986492)
		(end 87.301578 -277.244302)
		(width 0.254)
		(layer "F.Cu")
		(net "GND")
	)
	(segment
		(start 340.78418 -247.714262)
		(end 340.78418 -247.178576)
		(width 0.2032)
		(layer "F.Cu")
		(net "GND")
	)
	(segment
		(start 184.439814 -194.766692)
		(end 185.544714 -194.766692)
		(width 0.381)
		(layer "F.Cu")
		(net "GND")
	)
	(segment
		(start 342.773762 -276.708362)
		(end 342.774016 -276.708616)
		(width 0.2032)
		(layer "F.Cu")
		(net "GND")
	)
	(segment
		(start 215.719914 -286.56661)
		(end 216.824814 -286.56661)
		(width 0.381)
		(layer "F.Cu")
		(net "GND")
	)
	(segment
		(start 394.899642 -63.23203)
		(end 394.899896 -63.232284)
		(width 0.3556)
		(layer "F.Cu")
		(net "GND")
	)
	(segment
		(start 458.455014 -276.366732)
		(end 459.559914 -276.366732)
		(width 0.381)
		(layer "F.Cu")
		(net "GND")
	)
	(segment
		(start 439.923682 -280.61666)
		(end 441.028582 -280.61666)
		(width 0.381)
		(layer "F.Cu")
		(net "GND")
	)
	(segment
		(start 420.156894 -11.26998)
		(end 420.156894 -10.16508)
		(width 0.3556)
		(layer "F.Cu")
		(net "GND")
	)
	(segment
		(start 95.193866 -245.27256)
		(end 95.193612 -245.272306)
		(width 0.2032)
		(layer "F.Cu")
		(net "GND")
	)
	(segment
		(start 452.016114 -261.916672)
		(end 450.911214 -261.916672)
		(width 0.381)
		(layer "F.Cu")
		(net "GND")
	)
	(segment
		(start 460.664814 -214.316564)
		(end 459.559914 -214.316564)
		(width 0.381)
		(layer "F.Cu")
		(net "GND")
	)
	(segment
		(start 173.900846 -223.666558)
		(end 172.795946 -223.666558)
		(width 0.381)
		(layer "F.Cu")
		(net "GND")
	)
	(segment
		(start 364.389162 -269.66164)
		(end 364.389416 -270.167862)
		(width 0.2032)
		(layer "F.Cu")
		(net "GND")
	)
	(segment
		(start 161.808414 -291.666676)
		(end 162.913314 -291.666676)
		(width 0.381)
		(layer "F.Cu")
		(net "GND")
	)
	(segment
		(start 23.228046 -231.316784)
		(end 24.332946 -231.316784)
		(width 0.381)
		(layer "F.Cu")
		(net "GND")
	)
	(segment
		(start 40.506396 -334.530954)
		(end 40.506396 -335.471262)
		(width 0.508)
		(layer "F.Cu")
		(net "GND")
	)
	(segment
		(start 274.163282 -210.066636)
		(end 275.268182 -210.066636)
		(width 0.381)
		(layer "F.Cu")
		(net "GND")
	)
	(segment
		(start 126.317248 -283.497782)
		(end 126.317248 -284.033468)
		(width 0.254)
		(layer "F.Cu")
		(net "GND")
	)
	(segment
		(start 131.016248 -266.127992)
		(end 131.015994 -266.128246)
		(width 0.254)
		(layer "F.Cu")
		(net "GND")
	)
	(segment
		(start 383.07518 -247.714262)
		(end 383.075434 -247.714008)
		(width 0.2032)
		(layer "F.Cu")
		(net "GND")
	)
	(segment
		(start 215.719914 -213.46668)
		(end 216.824814 -213.46668)
		(width 0.381)
		(layer "F.Cu")
		(net "GND")
	)
	(segment
		(start 34.871914 -210.066636)
		(end 35.976814 -210.066636)
		(width 0.381)
		(layer "F.Cu")
		(net "GND")
	)
	(segment
		(start 210.514946 -206.666592)
		(end 211.619846 -206.666592)
		(width 0.381)
		(layer "F.Cu")
		(net "GND")
	)
	(segment
		(start 326.456294 -39.946072)
		(end 326.584818 -39.946072)
		(width 0.2032)
		(layer "F.Cu")
		(net "GND")
	)
	(segment
		(start 203.813918 -100.056696)
		(end 203.76388 -100.006658)
		(width 0.3556)
		(layer "F.Cu")
		(net "GND")
	)
	(segment
		(start 336.085434 -214.622888)
		(end 336.08518 -214.622634)
		(width 0.2032)
		(layer "F.Cu")
		(net "GND")
	)
	(segment
		(start 444.472314 -238.966756)
		(end 445.577214 -238.966756)
		(width 0.381)
		(layer "F.Cu")
		(net "GND")
	)
	(segment
		(start 337.495134 -233.87812)
		(end 337.49488 -233.877866)
		(width 0.2032)
		(layer "F.Cu")
		(net "GND")
	)
	(segment
		(start 453.121014 -251.716794)
		(end 452.016114 -251.716794)
		(width 0.381)
		(layer "F.Cu")
		(net "GND")
	)
	(segment
		(start 378.486162 -281.05608)
		(end 378.486416 -281.59202)
		(width 0.254)
		(layer "F.Cu")
		(net "GND")
	)
	(segment
		(start 137.484866 -223.575626)
		(end 137.484866 -224.111566)
		(width 0.2032)
		(layer "F.Cu")
		(net "GND")
	)
	(segment
		(start 336.665316 -262.336534)
		(end 336.665316 -262.87222)
		(width 0.2032)
		(layer "F.Cu")
		(net "GND")
	)
	(segment
		(start 458.455014 -317.166752)
		(end 459.559914 -317.166752)
		(width 0.381)
		(layer "F.Cu")
		(net "GND")
	)
	(segment
		(start 337.900264 -58.43524)
		(end 337.900264 -59.265312)
		(width 0.1016)
		(layer "F.Cu")
		(net "GND")
	)
	(segment
		(start 8.140446 -231.316784)
		(end 9.245346 -231.316784)
		(width 0.381)
		(layer "F.Cu")
		(net "GND")
	)
	(segment
		(start 39.420546 -268.71676)
		(end 38.315646 -268.71676)
		(width 0.381)
		(layer "F.Cu")
		(net "GND")
	)
	(segment
		(start 297.899582 -205.816708)
		(end 299.004482 -205.816708)
		(width 0.381)
		(layer "F.Cu")
		(net "GND")
	)
	(segment
		(start 272.273014 -231.316784)
		(end 271.168114 -231.316784)
		(width 0.381)
		(layer "F.Cu")
		(net "GND")
	)
	(segment
		(start 202.971146 -223.666558)
		(end 204.076046 -223.666558)
		(width 0.381)
		(layer "F.Cu")
		(net "GND")
	)
	(segment
		(start 441.028582 -312.91657)
		(end 442.133482 -312.91657)
		(width 0.381)
		(layer "F.Cu")
		(net "GND")
	)
	(segment
		(start 188.988446 -197.316598)
		(end 187.883546 -197.316598)
		(width 0.381)
		(layer "F.Cu")
		(net "GND")
	)
	(segment
		(start 420.736014 -250.016772)
		(end 421.840914 -250.016772)
		(width 0.381)
		(layer "F.Cu")
		(net "GND")
	)
	(segment
		(start 112.110266 -215.972644)
		(end 112.110266 -215.436958)
		(width 0.2032)
		(layer "F.Cu")
		(net "GND")
	)
	(segment
		(start 123.027694 -256.639314)
		(end 123.027694 -256.807462)
		(width 0.2032)
		(layer "F.Cu")
		(net "GND")
	)
	(segment
		(start 305.443382 -299.316648)
		(end 306.548282 -299.316648)
		(width 0.381)
		(layer "F.Cu")
		(net "GND")
	)
	(segment
		(start 102.712266 -231.714802)
		(end 102.712012 -231.714548)
		(width 0.254)
		(layer "F.Cu")
		(net "GND")
	)
	(segment
		(start 136.545066 -215.972644)
		(end 136.545066 -215.436958)
		(width 0.254)
		(layer "F.Cu")
		(net "GND")
	)
	(segment
		(start 254.975614 -251.716794)
		(end 256.080514 -251.716794)
		(width 0.381)
		(layer "F.Cu")
		(net "GND")
	)
	(segment
		(start 349.822516 -287.288986)
		(end 349.822262 -287.28924)
		(width 0.254)
		(layer "F.Cu")
		(net "GND")
	)
	(segment
		(start 65.047114 -297.616626)
		(end 66.152014 -297.616626)
		(width 0.381)
		(layer "F.Cu")
		(net "GND")
	)
	(segment
		(start 20.889214 -196.466714)
		(end 19.784314 -196.466714)
		(width 0.381)
		(layer "F.Cu")
		(net "GND")
	)
	(segment
		(start 115.869466 -217.600276)
		(end 115.869466 -217.064336)
		(width 0.254)
		(layer "F.Cu")
		(net "GND")
	)
	(segment
		(start 285.150814 -242.3668)
		(end 286.255714 -242.3668)
		(width 0.381)
		(layer "F.Cu")
		(net "GND")
	)
	(segment
		(start 114.099848 -273.730974)
		(end 114.099594 -274.266914)
		(width 0.254)
		(layer "F.Cu")
		(net "GND")
	)
	(segment
		(start 459.559914 -238.966756)
		(end 458.455014 -238.966756)
		(width 0.381)
		(layer "F.Cu")
		(net "GND")
	)
	(segment
		(start 7.035546 -298.466764)
		(end 8.140446 -298.466764)
		(width 0.381)
		(layer "F.Cu")
		(net "GND")
	)
	(segment
		(start 336.665316 -257.988816)
		(end 336.665062 -257.98907)
		(width 0.2032)
		(layer "F.Cu")
		(net "GND")
	)
	(segment
		(start 245.311168 -89.143586)
		(end 245.311168 -86.708742)
		(width 0.3556)
		(layer "F.Cu")
		(net "GND")
	)
	(segment
		(start 14.579346 -204.96657)
		(end 15.684246 -204.96657)
		(width 0.381)
		(layer "F.Cu")
		(net "GND")
	)
	(segment
		(start 328.625708 -49.390046)
		(end 328.244962 -49.950878)
		(width 0.1778)
		(layer "F.Cu")
		(net "GND")
	)
	(segment
		(start 57.503314 -200.716642)
		(end 58.608214 -200.716642)
		(width 0.381)
		(layer "F.Cu")
		(net "GND")
	)
	(segment
		(start 453.121014 -311.216802)
		(end 452.016114 -311.216802)
		(width 0.381)
		(layer "F.Cu")
		(net "GND")
	)
	(segment
		(start 406.753314 -203.266802)
		(end 407.858214 -203.266802)
		(width 0.381)
		(layer "F.Cu")
		(net "GND")
	)
	(segment
		(start 456.116182 -271.266666)
		(end 455.011282 -271.266666)
		(width 0.381)
		(layer "F.Cu")
		(net "GND")
	)
	(segment
		(start 83.726528 -277.410672)
		(end 84.964524 -276.172676)
		(width 0.2032)
		(layer "F.Cu")
		(net "GND")
	)
	(segment
		(start 449.677282 -261.066788)
		(end 448.572382 -261.066788)
		(width 0.381)
		(layer "F.Cu")
		(net "GND")
	)
	(segment
		(start 435.823614 -298.466764)
		(end 436.928514 -298.466764)
		(width 0.381)
		(layer "F.Cu")
		(net "GND")
	)
	(segment
		(start 441.028582 -219.41663)
		(end 442.133482 -219.41663)
		(width 0.381)
		(layer "F.Cu")
		(net "GND")
	)
	(segment
		(start 420.025068 -103.691436)
		(end 420.025068 -104.20731)
		(width 0.254)
		(layer "F.Cu")
		(net "GND")
	)
	(segment
		(start 123.78436 -416.903408)
		(end 123.3043 -417.383468)
		(width 0.3556)
		(layer "F.Cu")
		(net "GND")
	)
	(segment
		(start 427.045882 -294.216582)
		(end 425.940982 -294.216582)
		(width 0.381)
		(layer "F.Cu")
		(net "GND")
	)
	(segment
		(start 137.124948 -265.314176)
		(end 137.594594 -265.592306)
		(width 0.254)
		(layer "F.Cu")
		(net "GND")
	)
	(segment
		(start 137.124948 -283.219398)
		(end 137.124948 -283.219906)
		(width 0.254)
		(layer "F.Cu")
		(net "GND")
	)
	(segment
		(start 411.958282 -282.316682)
		(end 410.853382 -282.316682)
		(width 0.381)
		(layer "F.Cu")
		(net "GND")
	)
	(segment
		(start 409.748482 -222.816674)
		(end 410.853382 -222.816674)
		(width 0.381)
		(layer "F.Cu")
		(net "GND")
	)
	(segment
		(start 137.733024 -347.96349)
		(end 137.635488 -348.061026)
		(width 0.3556)
		(layer "F.Cu")
		(net "GND")
	)
	(segment
		(start 137.594594 -280.242264)
		(end 137.594594 -280.778204)
		(width 0.254)
		(layer "F.Cu")
		(net "GND")
	)
	(segment
		(start 244.18671 -253.363984)
		(end 244.80012 -253.363984)
		(width 0.3556)
		(layer "F.Cu")
		(net "GND")
	)
	(segment
		(start 204.076046 -250.016772)
		(end 205.180946 -250.016772)
		(width 0.381)
		(layer "F.Cu")
		(net "GND")
	)
	(segment
		(start 367.208562 -277.800562)
		(end 367.208816 -278.336502)
		(width 0.254)
		(layer "F.Cu")
		(net "GND")
	)
	(segment
		(start 339.484716 -283.497782)
		(end 339.484462 -283.498036)
		(width 0.254)
		(layer "F.Cu")
		(net "GND")
	)
	(segment
		(start 278.711914 -210.916774)
		(end 279.816814 -210.916774)
		(width 0.381)
		(layer "F.Cu")
		(net "GND")
	)
	(segment
		(start 432.379882 -238.116618)
		(end 433.484782 -238.116618)
		(width 0.381)
		(layer "F.Cu")
		(net "GND")
	)
	(segment
		(start 459.559914 -267.016738)
		(end 458.455014 -267.016738)
		(width 0.381)
		(layer "F.Cu")
		(net "GND")
	)
	(segment
		(start 385.424934 -223.575626)
		(end 385.424934 -224.111566)
		(width 0.2032)
		(layer "F.Cu")
		(net "GND")
	)
	(segment
		(start 91.904312 -247.714262)
		(end 91.904312 -247.178322)
		(width 0.2032)
		(layer "F.Cu")
		(net "GND")
	)
	(segment
		(start 266.619482 -238.116618)
		(end 267.724382 -238.116618)
		(width 0.381)
		(layer "F.Cu")
		(net "GND")
	)
	(segment
		(start 176.459388 -414.697418)
		(end 177.068988 -414.697418)
		(width 0.381)
		(layer "F.Cu")
		(net "GND")
	)
	(segment
		(start 281.707082 -221.116652)
		(end 282.811982 -221.116652)
		(width 0.381)
		(layer "F.Cu")
		(net "GND")
	)
	(segment
		(start 358.280716 -283.497782)
		(end 358.280716 -284.033468)
		(width 0.254)
		(layer "F.Cu")
		(net "GND")
	)
	(segment
		(start 150.93696 -130.632962)
		(end 150.93696 -130.036062)
		(width 0.3556)
		(layer "F.Cu")
		(net "GND")
	)
	(segment
		(start 5.694426 -98.516694)
		(end 5.694426 -97.778062)
		(width 0.3556)
		(layer "F.Cu")
		(net "GND")
	)
	(segment
		(start 413.01797 -311.216802)
		(end 414.297114 -311.216802)
		(width 0.381)
		(layer "F.Cu")
		(net "GND")
	)
	(segment
		(start 11.351768 -73.821798)
		(end 10.538968 -73.821798)
		(width 0.3556)
		(layer "F.Cu")
		(net "GND")
	)
	(segment
		(start 380.835916 -273.730974)
		(end 380.835916 -274.266914)
		(width 0.2032)
		(layer "F.Cu")
		(net "GND")
	)
	(segment
		(start 202.971146 -216.016586)
		(end 204.076046 -216.016586)
		(width 0.381)
		(layer "F.Cu")
		(net "GND")
	)
	(segment
		(start 166.357046 -248.31675)
		(end 167.461946 -248.31675)
		(width 0.381)
		(layer "F.Cu")
		(net "GND")
	)
	(segment
		(start 57.503314 -288.266632)
		(end 58.824114 -288.266632)
		(width 0.381)
		(layer "F.Cu")
		(net "GND")
	)
	(segment
		(start 272.273014 -220.266768)
		(end 271.168114 -220.266768)
		(width 0.381)
		(layer "F.Cu")
		(net "GND")
	)
	(segment
		(start 126.676912 -247.714262)
		(end 126.676912 -247.178322)
		(width 0.2032)
		(layer "F.Cu")
		(net "GND")
	)
	(segment
		(start 43.520614 -239.81664)
		(end 42.415714 -239.81664)
		(width 0.381)
		(layer "F.Cu")
		(net "GND")
	)
	(segment
		(start 339.014562 -263.68629)
		(end 339.014816 -263.686544)
		(width 0.2032)
		(layer "F.Cu")
		(net "GND")
	)
	(segment
		(start 358.170734 -220.855794)
		(end 358.170734 -220.319854)
		(width 0.2032)
		(layer "F.Cu")
		(net "GND")
	)
	(segment
		(start 211.6582 -98.171)
		(end 211.1248 -97.6376)
		(width 0.3556)
		(layer "F.Cu")
		(net "GND")
	)
	(segment
		(start 463.659982 -271.266666)
		(end 464.764882 -271.266666)
		(width 0.381)
		(layer "F.Cu")
		(net "GND")
	)
	(segment
		(start 305.443382 -228.766624)
		(end 306.548282 -228.766624)
		(width 0.381)
		(layer "F.Cu")
		(net "GND")
	)
	(segment
		(start 272.273014 -309.51678)
		(end 271.168114 -309.51678)
		(width 0.381)
		(layer "F.Cu")
		(net "GND")
	)
	(segment
		(start 448.572382 -314.616592)
		(end 447.467482 -314.616592)
		(width 0.381)
		(layer "F.Cu")
		(net "GND")
	)
	(segment
		(start 123.967494 -255.011682)
		(end 123.967494 -255.547368)
		(width 0.2032)
		(layer "F.Cu")
		(net "GND")
	)
	(segment
		(start 334.899508 -44.849796)
		(end 335.299558 -45.249846)
		(width 0.2032)
		(layer "F.Cu")
		(net "GND")
	)
	(segment
		(start 208.176114 -305.266598)
		(end 209.281014 -305.266598)
		(width 0.381)
		(layer "F.Cu")
		(net "GND")
	)
	(segment
		(start 161.808414 -244.066568)
		(end 162.913314 -244.066568)
		(width 0.381)
		(layer "F.Cu")
		(net "GND")
	)
	(segment
		(start 170.457114 -288.266632)
		(end 169.352214 -288.266632)
		(width 0.381)
		(layer "F.Cu")
		(net "GND")
	)
	(segment
		(start 98.482912 -223.297496)
		(end 98.482912 -222.76181)
		(width 0.254)
		(layer "F.Cu")
		(net "GND")
	)
	(segment
		(start 194.193414 -216.866724)
		(end 193.088514 -216.866724)
		(width 0.381)
		(layer "F.Cu")
		(net "GND")
	)
	(segment
		(start 457.221082 -277.216616)
		(end 456.116182 -277.216616)
		(width 0.381)
		(layer "F.Cu")
		(net "GND")
	)
	(segment
		(start 59.842146 -203.266802)
		(end 60.947046 -203.266802)
		(width 0.381)
		(layer "F.Cu")
		(net "GND")
	)
	(segment
		(start 285.150814 -244.916706)
		(end 286.255714 -244.916706)
		(width 0.381)
		(layer "F.Cu")
		(net "GND")
	)
	(segment
		(start 119.738648 -280.77795)
		(end 119.738394 -280.778204)
		(width 0.254)
		(layer "F.Cu")
		(net "GND")
	)
	(segment
		(start 378.016516 -272.103342)
		(end 378.016262 -272.639282)
		(width 0.2032)
		(layer "F.Cu")
		(net "GND")
	)
	(segment
		(start 125.267466 -250.155964)
		(end 125.267466 -249.620024)
		(width 0.2032)
		(layer "F.Cu")
		(net "GND")
	)
	(segment
		(start 165.048946 -273.816572)
		(end 166.357046 -273.816572)
		(width 0.381)
		(layer "F.Cu")
		(net "GND")
	)
	(segment
		(start 413.192214 -204.96657)
		(end 414.297114 -204.96657)
		(width 0.381)
		(layer "F.Cu")
		(net "GND")
	)
	(segment
		(start 360.050334 -237.133892)
		(end 360.05008 -237.133638)
		(width 0.2032)
		(layer "F.Cu")
		(net "GND")
	)
	(segment
		(start 436.928514 -227.066602)
		(end 438.033414 -227.066602)
		(width 0.381)
		(layer "F.Cu")
		(net "GND")
	)
	(segment
		(start 43.520614 -250.866656)
		(end 42.415714 -250.866656)
		(width 0.381)
		(layer "F.Cu")
		(net "GND")
	)
	(segment
		(start 130.906012 -237.133638)
		(end 130.906012 -236.597952)
		(width 0.254)
		(layer "F.Cu")
		(net "GND")
	)
	(segment
		(start 97.543112 -234.69219)
		(end 97.543366 -234.691936)
		(width 0.254)
		(layer "F.Cu")
		(net "GND")
	)
	(segment
		(start 296.074338 -363.25048)
		(end 295.747186 -363.25048)
		(width 0.2032)
		(layer "F.Cu")
		(net "GND")
	)
	(segment
		(start 377.076716 -270.475456)
		(end 377.076462 -271.011396)
		(width 0.2032)
		(layer "F.Cu")
		(net "GND")
	)
	(segment
		(start 178.000914 -222.816674)
		(end 176.896014 -222.816674)
		(width 0.381)
		(layer "F.Cu")
		(net "GND")
	)
	(segment
		(start 338.787994 -58.813192)
		(end 338.90077 -58.43524)
		(width 0.2032)
		(layer "F.Cu")
		(net "GND")
	)
	(segment
		(start 335.14538 -233.064304)
		(end 335.14538 -232.528618)
		(width 0.254)
		(layer "F.Cu")
		(net "GND")
	)
	(segment
		(start 129.026412 -238.76127)
		(end 129.026412 -238.225584)
		(width 0.2032)
		(layer "F.Cu")
		(net "GND")
	)
	(segment
		(start 89.555066 -230.622602)
		(end 89.554812 -230.622348)
		(width 0.2032)
		(layer "F.Cu")
		(net "GND")
	)
	(segment
		(start 197.637146 -265.316716)
		(end 196.532246 -265.316716)
		(width 0.381)
		(layer "F.Cu")
		(net "GND")
	)
	(segment
		(start 424.836082 -266.1666)
		(end 425.940982 -266.1666)
		(width 0.381)
		(layer "F.Cu")
		(net "GND")
	)
	(segment
		(start 215.719914 -306.96662)
		(end 216.824814 -306.96662)
		(width 0.381)
		(layer "F.Cu")
		(net "GND")
	)
	(segment
		(start 328.188828 -40.630094)
		(end 328.188828 -40.275002)
		(width 0.2032)
		(layer "F.Cu")
		(net "GND")
	)
	(segment
		(start 88.145366 -244.458744)
		(end 88.145366 -243.922804)
		(width 0.2032)
		(layer "F.Cu")
		(net "GND")
	)
	(segment
		(start 371.545358 -92.562934)
		(end 371.545358 -91.953334)
		(width 0.3556)
		(layer "F.Cu")
		(net "GND")
	)
	(segment
		(start 261.285482 -297.616626)
		(end 260.180582 -297.616626)
		(width 0.381)
		(layer "F.Cu")
		(net "GND")
	)
	(segment
		(start 350.126808 -59.95797)
		(end 349.712026 -59.543188)
		(width 0.2032)
		(layer "F.Cu")
		(net "GND")
	)
	(segment
		(start 344.073734 -242.017042)
		(end 344.07348 -242.016788)
		(width 0.2032)
		(layer "F.Cu")
		(net "GND")
	)
	(segment
		(start 435.823614 -217.716608)
		(end 436.928514 -217.716608)
		(width 0.381)
		(layer "F.Cu")
		(net "GND")
	)
	(segment
		(start 386.004562 -277.800562)
		(end 386.474462 -277.522432)
		(width 0.254)
		(layer "F.Cu")
		(net "GND")
	)
	(segment
		(start 43.520614 -261.066788)
		(end 42.415714 -261.066788)
		(width 0.381)
		(layer "F.Cu")
		(net "GND")
	)
	(segment
		(start 48.854614 -266.1666)
		(end 49.959514 -266.1666)
		(width 0.381)
		(layer "F.Cu")
		(net "GND")
	)
	(segment
		(start 266.619482 -261.066788)
		(end 267.724382 -261.066788)
		(width 0.381)
		(layer "F.Cu")
		(net "GND")
	)
	(segment
		(start 301.343314 -195.616576)
		(end 302.448214 -195.616576)
		(width 0.381)
		(layer "F.Cu")
		(net "GND")
	)
	(segment
		(start 42.415714 -303.566576)
		(end 41.310814 -303.566576)
		(width 0.381)
		(layer "F.Cu")
		(net "GND")
	)
	(segment
		(start 22.123146 -206.666592)
		(end 23.228046 -206.666592)
		(width 0.381)
		(layer "F.Cu")
		(net "GND")
	)
	(segment
		(start 15.684246 -270.416782)
		(end 16.789146 -270.416782)
		(width 0.381)
		(layer "F.Cu")
		(net "GND")
	)
	(segment
		(start 122.917712 -236.319822)
		(end 122.917966 -236.319568)
		(width 0.2032)
		(layer "F.Cu")
		(net "GND")
	)
	(segment
		(start 378.016516 -278.614378)
		(end 378.016516 -279.150318)
		(width 0.254)
		(layer "F.Cu")
		(net "GND")
	)
	(segment
		(start 27.547062 -10.16508)
		(end 27.547062 -11.26998)
		(width 0.3556)
		(layer "F.Cu")
		(net "GND")
	)
	(segment
		(start 54.508146 -203.266802)
		(end 53.403246 -203.266802)
		(width 0.381)
		(layer "F.Cu")
		(net "GND")
	)
	(segment
		(start 375.557034 -231.436164)
		(end 375.557034 -230.900478)
		(width 0.2032)
		(layer "F.Cu")
		(net "GND")
	)
	(segment
		(start 110.340648 -254.197612)
		(end 110.340648 -254.733806)
		(width 0.254)
		(layer "F.Cu")
		(net "GND")
	)
	(segment
		(start 154.966416 -30.941518)
		(end 154.966416 -30.312868)
		(width 0.3556)
		(layer "F.Cu")
		(net "GND")
	)
	(segment
		(start 56.867044 -8.320024)
		(end 56.867044 -7.215124)
		(width 0.3556)
		(layer "F.Cu")
		(net "GND")
	)
	(segment
		(start 382.135634 -215.158574)
		(end 382.135634 -214.546434)
		(width 0.254)
		(layer "F.Cu")
		(net "GND")
	)
	(segment
		(start 18.753328 -429.097948)
		(end 18.753328 -428.44974)
		(width 0.3556)
		(layer "F.Cu")
		(net "GND")
	)
	(segment
		(start 59.842146 -197.316598)
		(end 60.947046 -197.316598)
		(width 0.381)
		(layer "F.Cu")
		(net "GND")
	)
	(segment
		(start 129.026666 -220.855794)
		(end 129.026666 -220.319854)
		(width 0.2032)
		(layer "F.Cu")
		(net "GND")
	)
	(segment
		(start 137.484866 -227.367084)
		(end 136.545066 -226.831144)
		(width 0.254)
		(layer "F.Cu")
		(net "GND")
	)
	(segment
		(start 44.754546 -223.666558)
		(end 45.859446 -223.666558)
		(width 0.381)
		(layer "F.Cu")
		(net "GND")
	)
	(segment
		(start 348.412562 -279.428194)
		(end 348.412562 -279.96388)
		(width 0.254)
		(layer "F.Cu")
		(net "GND")
	)
	(segment
		(start 23.228046 -197.316598)
		(end 24.332946 -197.316598)
		(width 0.381)
		(layer "F.Cu")
		(net "GND")
	)
	(segment
		(start 126.676912 -216.78646)
		(end 126.676912 -216.250774)
		(width 0.254)
		(layer "F.Cu")
		(net "GND")
	)
	(segment
		(start 183.861964 -13.600176)
		(end 183.861964 -13.599922)
		(width 0.3556)
		(layer "F.Cu")
		(net "GND")
	)
	(segment
		(start 420.736014 -214.316564)
		(end 421.840914 -214.316564)
		(width 0.381)
		(layer "F.Cu")
		(net "GND")
	)
	(segment
		(start 212.39734 -69.86143)
		(end 212.39734 -69.202808)
		(width 0.3556)
		(layer "F.Cu")
		(net "GND")
	)
	(segment
		(start 361.45978 -226.017582)
		(end 361.460034 -226.017328)
		(width 0.254)
		(layer "F.Cu")
		(net "GND")
	)
	(segment
		(start 307.677312 -313.684158)
		(end 307.759862 -313.766708)
		(width 0.381)
		(layer "F.Cu")
		(net "GND")
	)
	(segment
		(start 29.666946 -283.166566)
		(end 30.771846 -283.166566)
		(width 0.381)
		(layer "F.Cu")
		(net "GND")
	)
	(segment
		(start 433.484782 -262.76681)
		(end 434.589682 -262.76681)
		(width 0.381)
		(layer "F.Cu")
		(net "GND")
	)
	(segment
		(start 326.080374 -37.87521)
		(end 326.193658 -37.983668)
		(width 0.2032)
		(layer "F.Cu")
		(net "GND")
	)
	(segment
		(start 305.443382 -289.966654)
		(end 306.548282 -289.966654)
		(width 0.381)
		(layer "F.Cu")
		(net "GND")
	)
	(segment
		(start 362.14558 -414.978088)
		(end 361.883706 -415.239962)
		(width 0.3556)
		(layer "F.Cu")
		(net "GND")
	)
	(segment
		(start 115.039648 -276.986492)
		(end 115.039648 -277.522178)
		(width 0.254)
		(layer "F.Cu")
		(net "GND")
	)
	(segment
		(start 44.754546 -261.916672)
		(end 45.859446 -261.916672)
		(width 0.381)
		(layer "F.Cu")
		(net "GND")
	)
	(segment
		(start 136.545066 -239.85347)
		(end 136.544812 -239.853216)
		(width 0.254)
		(layer "F.Cu")
		(net "GND")
	)
	(segment
		(start 44.754546 -313.766708)
		(end 45.859446 -313.766708)
		(width 0.381)
		(layer "F.Cu")
		(net "GND")
	)
	(segment
		(start 406.753314 -234.716574)
		(end 407.858214 -234.716574)
		(width 0.381)
		(layer "F.Cu")
		(net "GND")
	)
	(segment
		(start 52.298346 -268.71676)
		(end 53.403246 -268.71676)
		(width 0.381)
		(layer "F.Cu")
		(net "GND")
	)
	(segment
		(start 336.195162 -271.289272)
		(end 336.195162 -271.825212)
		(width 0.2032)
		(layer "F.Cu")
		(net "GND")
	)
	(segment
		(start 53.403246 -206.666592)
		(end 52.298346 -206.666592)
		(width 0.381)
		(layer "F.Cu")
		(net "GND")
	)
	(segment
		(start 389.97128 -28.717748)
		(end 391.006838 -27.68219)
		(width 0.3556)
		(layer "F.Cu")
		(net "GND")
	)
	(segment
		(start 188.988446 -236.416596)
		(end 187.883546 -236.416596)
		(width 0.381)
		(layer "F.Cu")
		(net "GND")
	)
	(segment
		(start 308.887114 -248.31675)
		(end 309.992014 -248.31675)
		(width 0.381)
		(layer "F.Cu")
		(net "GND")
	)
	(segment
		(start 368.618516 -280.77795)
		(end 368.618262 -280.778204)
		(width 0.254)
		(layer "F.Cu")
		(net "GND")
	)
	(segment
		(start 172.795946 -301.866808)
		(end 173.900846 -301.866808)
		(width 0.381)
		(layer "F.Cu")
		(net "GND")
	)
	(segment
		(start 102.386384 -335.541112)
		(end 102.135686 -335.79181)
		(width 0.1778)
		(layer "F.Cu")
		(net "GND")
	)
	(segment
		(start 27.328114 -200.716642)
		(end 28.433014 -200.716642)
		(width 0.381)
		(layer "F.Cu")
		(net "GND")
	)
	(segment
		(start 355.930962 -268.033754)
		(end 355.930962 -268.56944)
		(width 0.2032)
		(layer "F.Cu")
		(net "GND")
	)
	(segment
		(start 347.619066 -52.952396)
		(end 347.214698 -52.952396)
		(width 0.2032)
		(layer "F.Cu")
		(net "GND")
	)
	(segment
		(start 428.279814 -270.416782)
		(end 429.384714 -270.416782)
		(width 0.381)
		(layer "F.Cu")
		(net "GND")
	)
	(segment
		(start 135.245094 -274.54479)
		(end 135.245094 -275.08073)
		(width 0.2032)
		(layer "F.Cu")
		(net "GND")
	)
	(segment
		(start 415.418778 -182.785004)
		(end 415.418778 -183.032654)
		(width 0.2032)
		(layer "F.Cu")
		(net "GND")
	)
	(segment
		(start 173.900846 -195.616576)
		(end 172.795946 -195.616576)
		(width 0.381)
		(layer "F.Cu")
		(net "GND")
	)
	(segment
		(start 286.255714 -292.516814)
		(end 287.360614 -292.516814)
		(width 0.381)
		(layer "F.Cu")
		(net "GND")
	)
	(segment
		(start 272.36674 -92.563188)
		(end 272.059654 -92.870274)
		(width 0.3556)
		(layer "F.Cu")
		(net "GND")
	)
	(segment
		(start 272.273014 -307.816758)
		(end 271.168114 -307.816758)
		(width 0.381)
		(layer "F.Cu")
		(net "GND")
	)
	(segment
		(start 7.035546 -300.166786)
		(end 8.140446 -300.166786)
		(width 0.381)
		(layer "F.Cu")
		(net "GND")
	)
	(segment
		(start 127.726694 -272.917158)
		(end 127.726948 -273.453098)
		(width 0.2032)
		(layer "F.Cu")
		(net "GND")
	)
	(segment
		(start 314.094622 -53.228748)
		(end 314.685172 -53.228748)
		(width 0.381)
		(layer "F.Cu")
		(net "GND")
	)
	(segment
		(start 432.379882 -210.066636)
		(end 433.484782 -210.066636)
		(width 0.381)
		(layer "F.Cu")
		(net "GND")
	)
	(segment
		(start 136.075166 -216.25052)
		(end 136.075166 -216.78646)
		(width 0.2032)
		(layer "F.Cu")
		(net "GND")
	)
	(segment
		(start 278.711914 -270.416782)
		(end 279.816814 -270.416782)
		(width 0.381)
		(layer "F.Cu")
		(net "GND")
	)
	(segment
		(start 49.959514 -303.566576)
		(end 51.064414 -303.566576)
		(width 0.381)
		(layer "F.Cu")
		(net "GND")
	)
	(segment
		(start 335.615534 -248.528078)
		(end 335.615534 -247.992138)
		(width 0.2032)
		(layer "F.Cu")
		(net "GND")
	)
	(segment
		(start 175.005746 -210.916774)
		(end 173.900846 -210.916774)
		(width 0.381)
		(layer "F.Cu")
		(net "GND")
	)
	(segment
		(start 72.662034 -7.215124)
		(end 72.662034 -8.320024)
		(width 0.3556)
		(layer "F.Cu")
		(net "GND")
	)
	(segment
		(start 267.724382 -247.466612)
		(end 268.829282 -247.466612)
		(width 0.381)
		(layer "F.Cu")
		(net "GND")
	)
	(segment
		(start 92.844112 -249.342148)
		(end 92.844366 -249.341894)
		(width 0.2032)
		(layer "F.Cu")
		(net "GND")
	)
	(segment
		(start 329.980798 -44.691046)
		(end 329.980036 -44.691046)
		(width 0.254)
		(layer "F.Cu")
		(net "GND")
	)
	(segment
		(start 47.678594 -356.42423)
		(end 48.155606 -355.947218)
		(width 0.2032)
		(layer "F.Cu")
		(net "GND")
	)
	(segment
		(start 127.726694 -269.66164)
		(end 127.726948 -270.167862)
		(width 0.2032)
		(layer "F.Cu")
		(net "GND")
	)
	(segment
		(start 432.379882 -312.91657)
		(end 433.484782 -312.91657)
		(width 0.381)
		(layer "F.Cu")
		(net "GND")
	)
	(segment
		(start 290.355782 -235.566712)
		(end 291.460682 -235.566712)
		(width 0.381)
		(layer "F.Cu")
		(net "GND")
	)
	(segment
		(start 297.899582 -226.216718)
		(end 299.004482 -226.216718)
		(width 0.381)
		(layer "F.Cu")
		(net "GND")
	)
	(segment
		(start 324.6882 -20.333208)
		(end 324.6882 -20.632928)
		(width 0.3556)
		(layer "F.Cu")
		(net "GND")
	)
	(segment
		(start 378.956316 -267.219938)
		(end 378.956316 -267.755624)
		(width 0.254)
		(layer "F.Cu")
		(net "GND")
	)
	(segment
		(start 308.887114 -231.316784)
		(end 309.992014 -231.316784)
		(width 0.381)
		(layer "F.Cu")
		(net "GND")
	)
	(segment
		(start 116.449094 -279.96388)
		(end 116.449348 -279.964134)
		(width 0.254)
		(layer "F.Cu")
		(net "GND")
	)
	(segment
		(start 384.595116 -280.242264)
		(end 384.595116 -280.77795)
		(width 0.254)
		(layer "F.Cu")
		(net "GND")
	)
	(segment
		(start 169.041572 -421.527478)
		(end 168.431972 -421.527478)
		(width 0.381)
		(layer "F.Cu")
		(net "GND")
	)
	(segment
		(start 353.94138 -216.78646)
		(end 353.94138 -216.250774)
		(width 0.254)
		(layer "F.Cu")
		(net "GND")
	)
	(segment
		(start 135.605266 -228.45903)
		(end 135.605266 -228.99497)
		(width 0.254)
		(layer "F.Cu")
		(net "GND")
	)
	(segment
		(start 256.51333 -48.859186)
		(end 256.506218 -48.866298)
		(width 0.17272)
		(layer "F.Cu")
		(net "GND")
	)
	(segment
		(start 336.899758 -58.43524)
		(end 336.899758 -57.605168)
		(width 0.2032)
		(layer "F.Cu")
		(net "GND")
	)
	(segment
		(start 444.472314 -197.316598)
		(end 443.367414 -197.316598)
		(width 0.381)
		(layer "F.Cu")
		(net "GND")
	)
	(segment
		(start 328.895964 -60.07989)
		(end 328.895964 -59.265312)
		(width 0.2032)
		(layer "F.Cu")
		(net "GND")
	)
	(segment
		(start 336.195162 -281.05608)
		(end 336.195162 -281.59202)
		(width 0.254)
		(layer "F.Cu")
		(net "GND")
	)
	(segment
		(start 313.63539 -63.076328)
		(end 312.928 -63.076328)
		(width 0.3556)
		(layer "F.Cu")
		(net "GND")
	)
	(segment
		(start 166.357046 -217.716608)
		(end 167.461946 -217.716608)
		(width 0.381)
		(layer "F.Cu")
		(net "GND")
	)
	(segment
		(start 260.180582 -238.116618)
		(end 259.075682 -238.116618)
		(width 0.381)
		(layer "F.Cu")
		(net "GND")
	)
	(segment
		(start 117.749066 -220.855794)
		(end 117.749066 -220.319854)
		(width 0.2032)
		(layer "F.Cu")
		(net "GND")
	)
	(segment
		(start 338.90458 -216.250774)
		(end 338.904834 -216.25052)
		(width 0.254)
		(layer "F.Cu")
		(net "GND")
	)
	(segment
		(start 165.252146 -289.11677)
		(end 166.357046 -289.11677)
		(width 0.381)
		(layer "F.Cu")
		(net "GND")
	)
	(segment
		(start 220.487494 -97.13341)
		(end 221.1578 -97.13341)
		(width 0.3556)
		(layer "F.Cu")
		(net "GND")
	)
	(segment
		(start 179.105814 -258.516628)
		(end 178.000914 -258.516628)
		(width 0.381)
		(layer "F.Cu")
		(net "GND")
	)
	(segment
		(start 377.90628 -230.622348)
		(end 377.90628 -230.086662)
		(width 0.2032)
		(layer "F.Cu")
		(net "GND")
	)
	(segment
		(start 460.664814 -248.31675)
		(end 459.559914 -248.31675)
		(width 0.381)
		(layer "F.Cu")
		(net "GND")
	)
	(segment
		(start 87.315294 -279.428194)
		(end 87.315294 -279.964134)
		(width 0.2032)
		(layer "F.Cu")
		(net "GND")
	)
	(segment
		(start 371.79758 -220.041978)
		(end 371.797834 -220.041724)
		(width 0.254)
		(layer "F.Cu")
		(net "GND")
	)
	(segment
		(start 301.343314 -217.716608)
		(end 302.664114 -217.716608)
		(width 0.381)
		(layer "F.Cu")
		(net "GND")
	)
	(segment
		(start 311.882282 -232.166668)
		(end 312.987182 -232.166668)
		(width 0.381)
		(layer "F.Cu")
		(net "GND")
	)
	(segment
		(start 202.971146 -214.316564)
		(end 204.076046 -214.316564)
		(width 0.381)
		(layer "F.Cu")
		(net "GND")
	)
	(segment
		(start 380.365762 -266.405868)
		(end 380.365762 -266.941808)
		(width 0.2032)
		(layer "F.Cu")
		(net "GND")
	)
	(segment
		(start 115.483894 -406.21077)
		(end 115.483894 -405.57577)
		(width 0.3556)
		(layer "F.Cu")
		(net "GND")
	)
	(segment
		(start 379.896116 -283.497782)
		(end 379.896116 -284.033468)
		(width 0.254)
		(layer "F.Cu")
		(net "GND")
	)
	(segment
		(start 91.904312 -226.017582)
		(end 91.904566 -226.017328)
		(width 0.254)
		(layer "F.Cu")
		(net "GND")
	)
	(segment
		(start 275.268182 -303.566576)
		(end 276.373082 -303.566576)
		(width 0.381)
		(layer "F.Cu")
		(net "GND")
	)
	(segment
		(start 263.624314 -272.116804)
		(end 264.729214 -272.116804)
		(width 0.381)
		(layer "F.Cu")
		(net "GND")
	)
	(segment
		(start 26.223214 -310.366664)
		(end 27.328114 -310.366664)
		(width 0.381)
		(layer "F.Cu")
		(net "GND")
	)
	(segment
		(start 301.343314 -204.96657)
		(end 302.448214 -204.96657)
		(width 0.381)
		(layer "F.Cu")
		(net "GND")
	)
	(segment
		(start 128.666748 -270.167862)
		(end 128.666748 -270.19758)
		(width 0.2032)
		(layer "F.Cu")
		(net "GND")
	)
	(segment
		(start 304.338482 -247.466612)
		(end 305.443382 -247.466612)
		(width 0.381)
		(layer "F.Cu")
		(net "GND")
	)
	(segment
		(start 100.472494 -269.66164)
		(end 100.472494 -270.197326)
		(width 0.2032)
		(layer "F.Cu")
		(net "GND")
	)
	(segment
		(start 345.904058 -37.141912)
		(end 345.904058 -37.63518)
		(width 0.254)
		(layer "F.Cu")
		(net "GND")
	)
	(segment
		(start 43.520614 -200.716642)
		(end 42.415714 -200.716642)
		(width 0.381)
		(layer "F.Cu")
		(net "GND")
	)
	(segment
		(start 210.514946 -220.266768)
		(end 211.619846 -220.266768)
		(width 0.381)
		(layer "F.Cu")
		(net "GND")
	)
	(segment
		(start 374.257316 -280.242264)
		(end 374.257316 -280.778204)
		(width 0.254)
		(layer "F.Cu")
		(net "GND")
	)
	(segment
		(start 312.987182 -205.816708)
		(end 314.092082 -205.816708)
		(width 0.381)
		(layer "F.Cu")
		(net "GND")
	)
	(segment
		(start 300.238414 -197.316598)
		(end 301.343314 -197.316598)
		(width 0.381)
		(layer "F.Cu")
		(net "GND")
	)
	(segment
		(start 164.647626 -36.825428)
		(end 165.30066 -36.825428)
		(width 0.3556)
		(layer "F.Cu")
		(net "GND")
	)
	(segment
		(start 377.546362 -266.405868)
		(end 377.546616 -266.941808)
		(width 0.2032)
		(layer "F.Cu")
		(net "GND")
	)
	(segment
		(start 178.000914 -230.466646)
		(end 179.105814 -230.466646)
		(width 0.381)
		(layer "F.Cu")
		(net "GND")
	)
	(segment
		(start 448.572382 -205.816708)
		(end 447.467482 -205.816708)
		(width 0.381)
		(layer "F.Cu")
		(net "GND")
	)
	(segment
		(start 417.834572 -173.574202)
		(end 417.834572 -173.221904)
		(width 0.2032)
		(layer "F.Cu")
		(net "GND")
	)
	(segment
		(start 409.675838 -216.866724)
		(end 410.853382 -216.866724)
		(width 0.381)
		(layer "F.Cu")
		(net "GND")
	)
	(segment
		(start 88.693498 -181.73319)
		(end 88.693498 -180.92039)
		(width 0.3556)
		(layer "F.Cu")
		(net "GND")
	)
	(segment
		(start 42.415714 -305.266598)
		(end 41.310814 -305.266598)
		(width 0.381)
		(layer "F.Cu")
		(net "GND")
	)
	(segment
		(start 50.366422 -173.88078)
		(end 50.765964 -173.88078)
		(width 0.254)
		(layer "F.Cu")
		(net "GND")
	)
	(segment
		(start 267.724382 -233.86669)
		(end 268.829282 -233.86669)
		(width 0.381)
		(layer "F.Cu")
		(net "GND")
	)
	(segment
		(start 244.75694 -249.248168)
		(end 244.75694 -247.396508)
		(width 0.3556)
		(layer "F.Cu")
		(net "GND")
	)
	(segment
		(start 191.983614 -306.96662)
		(end 193.088514 -306.96662)
		(width 0.381)
		(layer "F.Cu")
		(net "GND")
	)
	(segment
		(start 359.58018 -214.622888)
		(end 359.579926 -214.622634)
		(width 0.1778)
		(layer "F.Cu")
		(net "GND")
	)
	(segment
		(start 385.070604 -273.453098)
		(end 385.064762 -273.453098)
		(width 0.254)
		(layer "F.Cu")
		(net "GND")
	)
	(segment
		(start 277.607014 -287.416748)
		(end 278.711914 -287.416748)
		(width 0.381)
		(layer "F.Cu")
		(net "GND")
	)
	(segment
		(start 457.221082 -200.716642)
		(end 456.116182 -200.716642)
		(width 0.381)
		(layer "F.Cu")
		(net "GND")
	)
	(segment
		(start 183.45658 -412.5468)
		(end 183.39816 -412.48838)
		(width 0.3556)
		(layer "F.Cu")
		(net "GND")
	)
	(segment
		(start 127.147066 -245.27256)
		(end 127.147066 -244.73662)
		(width 0.2032)
		(layer "F.Cu")
		(net "GND")
	)
	(segment
		(start 123.027694 -263.150604)
		(end 123.027694 -263.686544)
		(width 0.2032)
		(layer "F.Cu")
		(net "GND")
	)
	(segment
		(start 328.187812 -42.004234)
		(end 328.187812 -42.89044)
		(width 0.2032)
		(layer "F.Cu")
		(net "GND")
	)
	(segment
		(start 336.665316 -285.125414)
		(end 336.665062 -285.661354)
		(width 0.2032)
		(layer "F.Cu")
		(net "GND")
	)
	(segment
		(start 457.730098 -380.864872)
		(end 456.621388 -380.864872)
		(width 0.381)
		(layer "F.Cu")
		(net "GND")
	)
	(segment
		(start 104.701848 -274.26666)
		(end 104.701594 -274.266914)
		(width 0.2032)
		(layer "F.Cu")
		(net "GND")
	)
	(segment
		(start 87.785194 -263.96442)
		(end 87.785194 -264.50036)
		(width 0.254)
		(layer "F.Cu")
		(net "GND")
	)
	(segment
		(start 211.619846 -317.166752)
		(end 210.514946 -317.166752)
		(width 0.381)
		(layer "F.Cu")
		(net "GND")
	)
	(segment
		(start 120.715532 -14.20749)
		(end 121.47296 -14.20749)
		(width 0.3556)
		(layer "F.Cu")
		(net "GND")
	)
	(segment
		(start 193.088514 -294.216582)
		(end 194.193414 -294.216582)
		(width 0.381)
		(layer "F.Cu")
		(net "GND")
	)
	(segment
		(start 8.140446 -233.016806)
		(end 9.245346 -233.016806)
		(width 0.381)
		(layer "F.Cu")
		(net "GND")
	)
	(segment
		(start 433.484782 -226.216718)
		(end 434.589682 -226.216718)
		(width 0.381)
		(layer "F.Cu")
		(net "GND")
	)
	(segment
		(start 443.367414 -304.416714)
		(end 444.472314 -304.416714)
		(width 0.381)
		(layer "F.Cu")
		(net "GND")
	)
	(segment
		(start 157.708346 -233.016806)
		(end 158.813246 -233.016806)
		(width 0.381)
		(layer "F.Cu")
		(net "GND")
	)
	(segment
		(start 195.427346 -233.016806)
		(end 196.532246 -233.016806)
		(width 0.381)
		(layer "F.Cu")
		(net "GND")
	)
	(segment
		(start 180.339746 -234.716574)
		(end 181.444646 -234.716574)
		(width 0.381)
		(layer "F.Cu")
		(net "GND")
	)
	(segment
		(start 121.038112 -234.69219)
		(end 121.038112 -234.15625)
		(width 0.254)
		(layer "F.Cu")
		(net "GND")
	)
	(segment
		(start 127.616712 -246.08663)
		(end 127.616712 -245.55069)
		(width 0.2032)
		(layer "F.Cu")
		(net "GND")
	)
	(segment
		(start 138.064494 -271.289272)
		(end 138.534394 -271.011396)
		(width 0.254)
		(layer "F.Cu")
		(net "GND")
	)
	(segment
		(start 175.005746 -220.266768)
		(end 173.900846 -220.266768)
		(width 0.381)
		(layer "F.Cu")
		(net "GND")
	)
	(segment
		(start 87.785194 -254.197612)
		(end 87.785194 -254.733552)
		(width 0.254)
		(layer "F.Cu")
		(net "GND")
	)
	(segment
		(start 114.569494 -278.336248)
		(end 114.569748 -278.336502)
		(width 0.254)
		(layer "F.Cu")
		(net "GND")
	)
	(segment
		(start 369.088416 -281.591766)
		(end 369.088416 -281.59202)
		(width 0.254)
		(layer "F.Cu")
		(net "GND")
	)
	(segment
		(start 346.893134 -227.367084)
		(end 346.893134 -226.831144)
		(width 0.2032)
		(layer "F.Cu")
		(net "GND")
	)
	(segment
		(start 22.123146 -285.716726)
		(end 23.228046 -285.716726)
		(width 0.381)
		(layer "F.Cu")
		(net "GND")
	)
	(segment
		(start 101.27488 -356.160578)
		(end 101.046026 -356.389432)
		(width 0.381)
		(layer "F.Cu")
		(net "GND")
	)
	(segment
		(start 56.182514 -291.666676)
		(end 57.503314 -291.666676)
		(width 0.381)
		(layer "F.Cu")
		(net "GND")
	)
	(segment
		(start 207.071214 -291.666676)
		(end 208.176114 -291.666676)
		(width 0.381)
		(layer "F.Cu")
		(net "GND")
	)
	(segment
		(start 118.798848 -280.77795)
		(end 118.798594 -280.778204)
		(width 0.254)
		(layer "F.Cu")
		(net "GND")
	)
	(segment
		(start 373.317516 -280.242264)
		(end 373.317262 -280.778204)
		(width 0.254)
		(layer "F.Cu")
		(net "GND")
	)
	(segment
		(start 199.527414 -207.51673)
		(end 200.632314 -207.51673)
		(width 0.381)
		(layer "F.Cu")
		(net "GND")
	)
	(segment
		(start 201.40041 -120.614948)
		(end 202.02398 -120.614948)
		(width 0.3556)
		(layer "F.Cu")
		(net "GND")
	)
	(segment
		(start 266.619482 -312.91657)
		(end 267.724382 -312.91657)
		(width 0.381)
		(layer "F.Cu")
		(net "GND")
	)
	(segment
		(start 131.016248 -259.081016)
		(end 131.016248 -259.093462)
		(width 0.2032)
		(layer "F.Cu")
		(net "GND")
	)
	(segment
		(start 371.437916 -282.405582)
		(end 371.437662 -282.405836)
		(width 0.254)
		(layer "F.Cu")
		(net "GND")
	)
	(segment
		(start 289.250882 -282.316682)
		(end 290.355782 -282.316682)
		(width 0.381)
		(layer "F.Cu")
		(net "GND")
	)
	(segment
		(start 49.666906 -12.37488)
		(end 49.666906 -11.26998)
		(width 0.3556)
		(layer "F.Cu")
		(net "GND")
	)
	(segment
		(start 204.076046 -216.016586)
		(end 205.180946 -216.016586)
		(width 0.381)
		(layer "F.Cu")
		(net "GND")
	)
	(segment
		(start 435.823614 -287.416748)
		(end 436.928514 -287.416748)
		(width 0.381)
		(layer "F.Cu")
		(net "GND")
	)
	(segment
		(start 11.135614 -226.216718)
		(end 12.240514 -226.216718)
		(width 0.381)
		(layer "F.Cu")
		(net "GND")
	)
	(segment
		(start 202.971146 -304.416714)
		(end 204.076046 -304.416714)
		(width 0.381)
		(layer "F.Cu")
		(net "GND")
	)
	(segment
		(start 358.170734 -246.900446)
		(end 358.170734 -246.364506)
		(width 0.254)
		(layer "F.Cu")
		(net "GND")
	)
	(segment
		(start 208.176114 -310.366664)
		(end 209.281014 -310.366664)
		(width 0.381)
		(layer "F.Cu")
		(net "GND")
	)
	(segment
		(start 382.74244 -288.890202)
		(end 382.715516 -288.917126)
		(width 0.254)
		(layer "F.Cu")
		(net "GND")
	)
	(segment
		(start 107.880912 -226.553268)
		(end 107.880912 -226.017582)
		(width 0.254)
		(layer "F.Cu")
		(net "GND")
	)
	(segment
		(start 123.497848 -287.288986)
		(end 123.497594 -287.28924)
		(width 0.254)
		(layer "F.Cu")
		(net "GND")
	)
	(segment
		(start 422.945814 -289.11677)
		(end 421.840914 -289.11677)
		(width 0.381)
		(layer "F.Cu")
		(net "GND")
	)
	(segment
		(start 372.377716 -276.986492)
		(end 372.377462 -277.522432)
		(width 0.2032)
		(layer "F.Cu")
		(net "GND")
	)
	(segment
		(start 425.940982 -275.516594)
		(end 424.836082 -275.516594)
		(width 0.381)
		(layer "F.Cu")
		(net "GND")
	)
	(segment
		(start 139.214606 -248.680478)
		(end 140.062966 -248.680478)
		(width 0.2032)
		(layer "F.Cu")
		(net "GND")
	)
	(segment
		(start 262.519414 -296.766742)
		(end 263.624314 -296.766742)
		(width 0.381)
		(layer "F.Cu")
		(net "GND")
	)
	(segment
		(start 286.255714 -236.416596)
		(end 287.360614 -236.416596)
		(width 0.381)
		(layer "F.Cu")
		(net "GND")
	)
	(segment
		(start 93.784166 -233.06405)
		(end 93.784166 -232.528364)
		(width 0.254)
		(layer "F.Cu")
		(net "GND")
	)
	(segment
		(start 99.532694 -276.172676)
		(end 99.532694 -276.708362)
		(width 0.2032)
		(layer "F.Cu")
		(net "GND")
	)
	(segment
		(start 200.632314 -215.166702)
		(end 201.737214 -215.166702)
		(width 0.381)
		(layer "F.Cu")
		(net "GND")
	)
	(segment
		(start 90.964512 -220.041978)
		(end 90.964766 -220.041724)
		(width 0.254)
		(layer "F.Cu")
		(net "GND")
	)
	(segment
		(start 343.60358 -226.553268)
		(end 343.60358 -226.017582)
		(width 0.254)
		(layer "F.Cu")
		(net "GND")
	)
	(segment
		(start 432.379882 -295.916604)
		(end 433.484782 -295.916604)
		(width 0.381)
		(layer "F.Cu")
		(net "GND")
	)
	(segment
		(start 374.61698 -220.041978)
		(end 374.617234 -220.041724)
		(width 0.254)
		(layer "F.Cu")
		(net "GND")
	)
	(segment
		(start 383.545334 -224.111566)
		(end 383.545334 -223.575626)
		(width 0.2032)
		(layer "F.Cu")
		(net "GND")
	)
	(segment
		(start 128.196848 -278.614378)
		(end 128.196594 -279.150318)
		(width 0.2032)
		(layer "F.Cu")
		(net "GND")
	)
	(segment
		(start 464.764882 -272.966688)
		(end 463.659982 -272.966688)
		(width 0.381)
		(layer "F.Cu")
		(net "GND")
	)
	(segment
		(start 356.401116 -278.614378)
		(end 356.400862 -278.614632)
		(width 0.254)
		(layer "F.Cu")
		(net "GND")
	)
	(segment
		(start 441.028582 -289.966654)
		(end 442.133482 -289.966654)
		(width 0.381)
		(layer "F.Cu")
		(net "GND")
	)
	(segment
		(start 364.27918 -229.808786)
		(end 364.279434 -229.808532)
		(width 0.254)
		(layer "F.Cu")
		(net "GND")
	)
	(segment
		(start 102.712266 -214.344758)
		(end 102.712266 -213.732618)
		(width 0.254)
		(layer "F.Cu")
		(net "GND")
	)
	(segment
		(start 101.412294 -262.058404)
		(end 101.412548 -262.058658)
		(width 0.254)
		(layer "F.Cu")
		(net "GND")
	)
	(segment
		(start 44.754546 -279.766776)
		(end 45.859446 -279.766776)
		(width 0.381)
		(layer "F.Cu")
		(net "GND")
	)
	(segment
		(start 373.622316 -102.106984)
		(end 373.622316 -103.237284)
		(width 0.3556)
		(layer "F.Cu")
		(net "GND")
	)
	(segment
		(start 256.080514 -233.016806)
		(end 257.185414 -233.016806)
		(width 0.381)
		(layer "F.Cu")
		(net "GND")
	)
	(segment
		(start 332.796134 -243.644928)
		(end 332.796134 -243.108988)
		(width 0.2032)
		(layer "F.Cu")
		(net "GND")
	)
	(segment
		(start 294.904414 -251.716794)
		(end 293.799514 -251.716794)
		(width 0.381)
		(layer "F.Cu")
		(net "GND")
	)
	(segment
		(start 457.221082 -269.566644)
		(end 456.116182 -269.566644)
		(width 0.381)
		(layer "F.Cu")
		(net "GND")
	)
	(segment
		(start 354.051362 -279.96388)
		(end 354.051616 -279.964134)
		(width 0.254)
		(layer "F.Cu")
		(net "GND")
	)
	(segment
		(start 300.238414 -261.916672)
		(end 301.343314 -261.916672)
		(width 0.3556)
		(layer "F.Cu")
		(net "GND")
	)
	(segment
		(start 52.15128 -170.176698)
		(end 52.15128 -169.560748)
		(width 0.3556)
		(layer "F.Cu")
		(net "GND")
	)
	(segment
		(start 100.472494 -260.430518)
		(end 100.472748 -260.430772)
		(width 0.254)
		(layer "F.Cu")
		(net "GND")
	)
	(segment
		(start 33.767014 -196.466714)
		(end 34.871914 -196.466714)
		(width 0.381)
		(layer "F.Cu")
		(net "GND")
	)
	(segment
		(start 296.794682 -205.816708)
		(end 297.899582 -205.816708)
		(width 0.381)
		(layer "F.Cu")
		(net "GND")
	)
	(segment
		(start 43.520614 -277.216616)
		(end 42.415714 -277.216616)
		(width 0.381)
		(layer "F.Cu")
		(net "GND")
	)
	(segment
		(start 371.79758 -226.017582)
		(end 371.797834 -226.017328)
		(width 0.254)
		(layer "F.Cu")
		(net "GND")
	)
	(segment
		(start 316.996572 -56.759348)
		(end 316.996572 -57.775348)
		(width 0.381)
		(layer "F.Cu")
		(net "GND")
	)
	(segment
		(start 441.028582 -278.916638)
		(end 442.133482 -278.916638)
		(width 0.381)
		(layer "F.Cu")
		(net "GND")
	)
	(segment
		(start 429.384714 -281.466798)
		(end 430.489614 -281.466798)
		(width 0.381)
		(layer "F.Cu")
		(net "GND")
	)
	(segment
		(start 357.70058 -216.250774)
		(end 357.700834 -216.25052)
		(width 0.254)
		(layer "F.Cu")
		(net "GND")
	)
	(segment
		(start 136.655048 -267.219938)
		(end 136.655048 -267.755624)
		(width 0.254)
		(layer "F.Cu")
		(net "GND")
	)
	(segment
		(start 341.133176 -338.798916)
		(end 341.133176 -339.1154)
		(width 0.381)
		(layer "F.Cu")
		(net "GND")
	)
	(segment
		(start 91.904312 -237.947454)
		(end 91.904312 -237.411514)
		(width 0.254)
		(layer "F.Cu")
		(net "GND")
	)
	(segment
		(start 170.457114 -241.516662)
		(end 169.352214 -241.516662)
		(width 0.381)
		(layer "F.Cu")
		(net "GND")
	)
	(segment
		(start 418.397182 -284.866588)
		(end 417.292282 -284.866588)
		(width 0.381)
		(layer "F.Cu")
		(net "GND")
	)
	(segment
		(start 425.940982 -291.666676)
		(end 424.836082 -291.666676)
		(width 0.381)
		(layer "F.Cu")
		(net "GND")
	)
	(segment
		(start 419.502082 -297.616626)
		(end 418.397182 -297.616626)
		(width 0.381)
		(layer "F.Cu")
		(net "GND")
	)
	(segment
		(start 34.871914 -277.216616)
		(end 33.767014 -277.216616)
		(width 0.381)
		(layer "F.Cu")
		(net "GND")
	)
	(segment
		(start 85.813138 -339.586316)
		(end 85.260942 -340.138512)
		(width 0.1778)
		(layer "F.Cu")
		(net "GND")
	)
	(segment
		(start 27.328114 -262.76681)
		(end 28.433014 -262.76681)
		(width 0.381)
		(layer "F.Cu")
		(net "GND")
	)
	(segment
		(start 30.771846 -290.816792)
		(end 31.876746 -290.816792)
		(width 0.381)
		(layer "F.Cu")
		(net "GND")
	)
	(segment
		(start 267.724382 -282.316682)
		(end 268.829282 -282.316682)
		(width 0.381)
		(layer "F.Cu")
		(net "GND")
	)
	(segment
		(start 449.677282 -314.616592)
		(end 448.572382 -314.616592)
		(width 0.381)
		(layer "F.Cu")
		(net "GND")
	)
	(segment
		(start 456.116182 -280.61666)
		(end 455.011282 -280.61666)
		(width 0.381)
		(layer "F.Cu")
		(net "GND")
	)
	(segment
		(start 102.822248 -268.84757)
		(end 102.821994 -268.847824)
		(width 0.2032)
		(layer "F.Cu")
		(net "GND")
	)
	(segment
		(start 178.000914 -233.86669)
		(end 176.896014 -233.86669)
		(width 0.381)
		(layer "F.Cu")
		(net "GND")
	)
	(segment
		(start 450.737986 -111.133382)
		(end 451.658228 -111.133382)
		(width 0.3556)
		(layer "F.Cu")
		(net "GND")
	)
	(segment
		(start 197.637146 -301.866808)
		(end 196.532246 -301.866808)
		(width 0.381)
		(layer "F.Cu")
		(net "GND")
	)
	(segment
		(start 211.619846 -301.866808)
		(end 212.724746 -301.866808)
		(width 0.381)
		(layer "F.Cu")
		(net "GND")
	)
	(segment
		(start 445.577214 -208.366614)
		(end 444.472314 -208.366614)
		(width 0.381)
		(layer "F.Cu")
		(net "GND")
	)
	(segment
		(start 49.959514 -249.166634)
		(end 51.064414 -249.166634)
		(width 0.381)
		(layer "F.Cu")
		(net "GND")
	)
	(segment
		(start 361.569762 -255.011682)
		(end 361.569762 -255.547622)
		(width 0.254)
		(layer "F.Cu")
		(net "GND")
	)
	(segment
		(start 364.27918 -222.76181)
		(end 364.279434 -222.761556)
		(width 0.254)
		(layer "F.Cu")
		(net "GND")
	)
	(segment
		(start 190.093346 -265.316716)
		(end 188.988446 -265.316716)
		(width 0.381)
		(layer "F.Cu")
		(net "GND")
	)
	(segment
		(start 374.257316 -287.288986)
		(end 374.257062 -287.28924)
		(width 0.254)
		(layer "F.Cu")
		(net "GND")
	)
	(segment
		(start 119.268494 -282.683966)
		(end 119.268494 -283.219906)
		(width 0.254)
		(layer "F.Cu")
		(net "GND")
	)
	(segment
		(start 207.071214 -235.566712)
		(end 208.176114 -235.566712)
		(width 0.381)
		(layer "F.Cu")
		(net "GND")
	)
	(segment
		(start 85.43798 -103.200708)
		(end 85.379052 -103.259636)
		(width 0.3556)
		(layer "F.Cu")
		(net "GND")
	)
	(segment
		(start 342.66378 -216.78646)
		(end 342.664034 -216.786206)
		(width 0.254)
		(layer "F.Cu")
		(net "GND")
	)
	(segment
		(start 300.238414 -298.466764)
		(end 301.343314 -298.466764)
		(width 0.381)
		(layer "F.Cu")
		(net "GND")
	)
	(segment
		(start 357.148892 -389.19277)
		(end 356.51186 -389.19277)
		(width 0.3556)
		(layer "F.Cu")
		(net "GND")
	)
	(segment
		(start 39.420546 -212.616796)
		(end 38.315646 -212.616796)
		(width 0.381)
		(layer "F.Cu")
		(net "GND")
	)
	(segment
		(start 452.016114 -248.31675)
		(end 450.911214 -248.31675)
		(width 0.381)
		(layer "F.Cu")
		(net "GND")
	)
	(segment
		(start 138.894312 -226.553268)
		(end 139.834366 -226.017328)
		(width 0.254)
		(layer "F.Cu")
		(net "GND")
	)
	(segment
		(start 63.726314 -210.066636)
		(end 65.047114 -210.066636)
		(width 0.381)
		(layer "F.Cu")
		(net "GND")
	)
	(segment
		(start 335.899252 -39.295324)
		(end 336.399632 -39.443152)
		(width 0.2032)
		(layer "F.Cu")
		(net "GND")
	)
	(segment
		(start 170.457114 -196.466714)
		(end 171.562014 -196.466714)
		(width 0.381)
		(layer "F.Cu")
		(net "GND")
	)
	(segment
		(start 369.918234 -234.691936)
		(end 369.918234 -234.15625)
		(width 0.254)
		(layer "F.Cu")
		(net "GND")
	)
	(segment
		(start 293.645844 -414.04286)
		(end 293.645844 -415.00552)
		(width 0.3556)
		(layer "F.Cu")
		(net "GND")
	)
	(segment
		(start 345.026234 -47.949612)
		(end 345.554554 -47.95012)
		(width 0.1778)
		(layer "F.Cu")
		(net "GND")
	)
	(segment
		(start 191.983614 -316.316614)
		(end 193.088514 -316.316614)
		(width 0.381)
		(layer "F.Cu")
		(net "GND")
	)
	(segment
		(start 254.975614 -281.466798)
		(end 256.080514 -281.466798)
		(width 0.381)
		(layer "F.Cu")
		(net "GND")
	)
	(segment
		(start 173.900846 -258.516628)
		(end 172.795946 -258.516628)
		(width 0.381)
		(layer "F.Cu")
		(net "GND")
	)
	(segment
		(start 27.328114 -210.066636)
		(end 28.433014 -210.066636)
		(width 0.381)
		(layer "F.Cu")
		(net "GND")
	)
	(segment
		(start 188.988446 -220.266768)
		(end 187.883546 -220.266768)
		(width 0.381)
		(layer "F.Cu")
		(net "GND")
	)
	(segment
		(start 158.813246 -201.56678)
		(end 159.918146 -201.56678)
		(width 0.381)
		(layer "F.Cu")
		(net "GND")
	)
	(segment
		(start 245.311168 -90.202258)
		(end 245.760494 -90.651584)
		(width 0.3556)
		(layer "F.Cu")
		(net "GND")
	)
	(segment
		(start 215.72855 -120.142)
		(end 215.0618 -120.142)
		(width 0.3556)
		(layer "F.Cu")
		(net "GND")
	)
	(segment
		(start 293.799514 -221.96679)
		(end 292.694614 -221.96679)
		(width 0.381)
		(layer "F.Cu")
		(net "GND")
	)
	(segment
		(start 365.21898 -223.297496)
		(end 365.21898 -222.76181)
		(width 0.254)
		(layer "F.Cu")
		(net "GND")
	)
	(segment
		(start 448.572382 -194.766692)
		(end 449.677282 -194.766692)
		(width 0.381)
		(layer "F.Cu")
		(net "GND")
	)
	(segment
		(start 340.424516 -281.869896)
		(end 340.42477 -281.87015)
		(width 0.254)
		(layer "F.Cu")
		(net "GND")
	)
	(segment
		(start 211.619846 -229.616762)
		(end 210.514946 -229.616762)
		(width 0.381)
		(layer "F.Cu")
		(net "GND")
	)
	(segment
		(start 7.035546 -283.166566)
		(end 8.140446 -283.166566)
		(width 0.381)
		(layer "F.Cu")
		(net "GND")
	)
	(segment
		(start 366.268762 -283.219652)
		(end 366.269016 -283.219906)
		(width 0.254)
		(layer "F.Cu")
		(net "GND")
	)
	(segment
		(start 378.846334 -248.528078)
		(end 378.846334 -247.992138)
		(width 0.2032)
		(layer "F.Cu")
		(net "GND")
	)
	(segment
		(start 394.84681 -8.320024)
		(end 394.84681 -7.215124)
		(width 0.3556)
		(layer "F.Cu")
		(net "GND")
	)
	(segment
		(start 131.846066 -245.27256)
		(end 131.846066 -244.73662)
		(width 0.2032)
		(layer "F.Cu")
		(net "GND")
	)
	(segment
		(start 21.348192 -399.932144)
		(end 21.348192 -400.814032)
		(width 0.4572)
		(layer "F.Cu")
		(net "GND")
	)
	(segment
		(start 254.975614 -199.01662)
		(end 256.080514 -199.01662)
		(width 0.381)
		(layer "F.Cu")
		(net "GND")
	)
	(segment
		(start 447.467482 -235.566712)
		(end 448.572382 -235.566712)
		(width 0.381)
		(layer "F.Cu")
		(net "GND")
	)
	(segment
		(start 158.813246 -250.016772)
		(end 159.918146 -250.016772)
		(width 0.381)
		(layer "F.Cu")
		(net "GND")
	)
	(segment
		(start 256.080514 -195.616576)
		(end 257.185414 -195.616576)
		(width 0.381)
		(layer "F.Cu")
		(net "GND")
	)
	(segment
		(start 337.02498 -224.925382)
		(end 337.02498 -224.389696)
		(width 0.254)
		(layer "F.Cu")
		(net "GND")
	)
	(segment
		(start 418.397182 -216.866724)
		(end 417.076128 -216.866724)
		(width 0.381)
		(layer "F.Cu")
		(net "GND")
	)
	(segment
		(start 106.941112 -216.78646)
		(end 106.941112 -216.250774)
		(width 0.254)
		(layer "F.Cu")
		(net "GND")
	)
	(segment
		(start 214.615014 -221.116652)
		(end 215.719914 -221.116652)
		(width 0.381)
		(layer "F.Cu")
		(net "GND")
	)
	(segment
		(start 380.25578 -246.08663)
		(end 380.25578 -245.55069)
		(width 0.2032)
		(layer "F.Cu")
		(net "GND")
	)
	(segment
		(start 63.942214 -224.516696)
		(end 65.047114 -224.516696)
		(width 0.381)
		(layer "F.Cu")
		(net "GND")
	)
	(segment
		(start 277.607014 -263.616694)
		(end 278.711914 -263.616694)
		(width 0.381)
		(layer "F.Cu")
		(net "GND")
	)
	(segment
		(start 197.637146 -311.216802)
		(end 196.532246 -311.216802)
		(width 0.381)
		(layer "F.Cu")
		(net "GND")
	)
	(segment
		(start 135.135112 -218.414346)
		(end 135.135112 -217.878406)
		(width 0.2032)
		(layer "F.Cu")
		(net "GND")
	)
	(segment
		(start 250.194064 -87.543386)
		(end 250.126754 -87.610696)
		(width 0.3556)
		(layer "F.Cu")
		(net "GND")
	)
	(segment
		(start 373.787162 -261.522718)
		(end 373.787162 -262.058658)
		(width 0.2032)
		(layer "F.Cu")
		(net "GND")
	)
	(segment
		(start 290.355782 -210.066636)
		(end 291.460682 -210.066636)
		(width 0.381)
		(layer "F.Cu")
		(net "GND")
	)
	(segment
		(start 91.434666 -232.250488)
		(end 91.434412 -232.250234)
		(width 0.2032)
		(layer "F.Cu")
		(net "GND")
	)
	(segment
		(start 187.883546 -311.216802)
		(end 188.988446 -311.216802)
		(width 0.381)
		(layer "F.Cu")
		(net "GND")
	)
	(segment
		(start 414.297114 -278.066754)
		(end 415.402014 -278.066754)
		(width 0.381)
		(layer "F.Cu")
		(net "GND")
	)
	(segment
		(start 256.080514 -240.666778)
		(end 257.185414 -240.666778)
		(width 0.381)
		(layer "F.Cu")
		(net "GND")
	)
	(segment
		(start 106.001312 -223.297496)
		(end 106.001312 -222.76181)
		(width 0.254)
		(layer "F.Cu")
		(net "GND")
	)
	(segment
		(start 8.140446 -292.516814)
		(end 9.245346 -292.516814)
		(width 0.381)
		(layer "F.Cu")
		(net "GND")
	)
	(segment
		(start 372.26748 -243.644674)
		(end 372.26748 -243.108988)
		(width 0.2032)
		(layer "F.Cu")
		(net "GND")
	)
	(segment
		(start 101.412294 -279.428194)
		(end 101.412294 -279.96388)
		(width 0.2032)
		(layer "F.Cu")
		(net "GND")
	)
	(segment
		(start 36.988496 -102.07879)
		(end 35.807396 -102.07879)
		(width 0.3556)
		(layer "F.Cu")
		(net "GND")
	)
	(segment
		(start 428.279814 -250.016772)
		(end 429.384714 -250.016772)
		(width 0.381)
		(layer "F.Cu")
		(net "GND")
	)
	(segment
		(start 379.425962 -282.683966)
		(end 379.426216 -282.68422)
		(width 0.254)
		(layer "F.Cu")
		(net "GND")
	)
	(segment
		(start 433.484782 -314.616592)
		(end 434.589682 -314.616592)
		(width 0.381)
		(layer "F.Cu")
		(net "GND")
	)
	(segment
		(start 202.971146 -195.616576)
		(end 204.076046 -195.616576)
		(width 0.381)
		(layer "F.Cu")
		(net "GND")
	)
	(segment
		(start 347.754702 -38.945566)
		(end 347.214698 -38.945566)
		(width 0.2032)
		(layer "F.Cu")
		(net "GND")
	)
	(segment
		(start 207.071214 -205.816708)
		(end 208.176114 -205.816708)
		(width 0.381)
		(layer "F.Cu")
		(net "GND")
	)
	(segment
		(start 114.569494 -277.800562)
		(end 114.569494 -278.336248)
		(width 0.254)
		(layer "F.Cu")
		(net "GND")
	)
	(segment
		(start 376.136916 -286.7533)
		(end 376.136916 -287.288986)
		(width 0.254)
		(layer "F.Cu")
		(net "GND")
	)
	(segment
		(start 133.255512 -242.295172)
		(end 133.255766 -242.294918)
		(width 0.2032)
		(layer "F.Cu")
		(net "GND")
	)
	(segment
		(start 439.923682 -258.516628)
		(end 441.028582 -258.516628)
		(width 0.381)
		(layer "F.Cu")
		(net "GND")
	)
	(segment
		(start 58.608214 -239.94364)
		(end 58.481214 -239.81664)
		(width 0.381)
		(layer "F.Cu")
		(net "GND")
	)
	(segment
		(start 48.4632 -171.618148)
		(end 48.60798 -171.473368)
		(width 0.3556)
		(layer "F.Cu")
		(net "GND")
	)
	(segment
		(start 458.455014 -289.11677)
		(end 459.559914 -289.11677)
		(width 0.381)
		(layer "F.Cu")
		(net "GND")
	)
	(segment
		(start 349.71228 -250.15571)
		(end 349.71228 -249.620024)
		(width 0.2032)
		(layer "F.Cu")
		(net "GND")
	)
	(segment
		(start 276.373082 -288.266632)
		(end 275.268182 -288.266632)
		(width 0.381)
		(layer "F.Cu")
		(net "GND")
	)
	(segment
		(start 394.84681 -11.26998)
		(end 394.84681 -12.37488)
		(width 0.3556)
		(layer "F.Cu")
		(net "GND")
	)
	(segment
		(start 103.762048 -275.894546)
		(end 103.761794 -275.8948)
		(width 0.2032)
		(layer "F.Cu")
		(net "GND")
	)
	(segment
		(start 56.398414 -249.166634)
		(end 57.503314 -249.166634)
		(width 0.381)
		(layer "F.Cu")
		(net "GND")
	)
	(segment
		(start 136.655048 -285.125414)
		(end 136.654794 -285.125668)
		(width 0.2032)
		(layer "F.Cu")
		(net "GND")
	)
	(segment
		(start 127.616966 -247.714008)
		(end 127.616966 -247.178322)
		(width 0.2032)
		(layer "F.Cu")
		(net "GND")
	)
	(segment
		(start 418.397182 -239.81664)
		(end 417.292282 -239.81664)
		(width 0.381)
		(layer "F.Cu")
		(net "GND")
	)
	(segment
		(start 334.024732 -342.108028)
		(end 334.024732 -342.769952)
		(width 0.381)
		(layer "F.Cu")
		(net "GND")
	)
	(segment
		(start 63.942214 -295.916604)
		(end 65.047114 -295.916604)
		(width 0.381)
		(layer "F.Cu")
		(net "GND")
	)
	(segment
		(start 276.373082 -235.566712)
		(end 275.268182 -235.566712)
		(width 0.381)
		(layer "F.Cu")
		(net "GND")
	)
	(segment
		(start 462.555082 -219.41663)
		(end 463.659982 -219.41663)
		(width 0.381)
		(layer "F.Cu")
		(net "GND")
	)
	(segment
		(start 307.566314 -208.366614)
		(end 308.887114 -208.366614)
		(width 0.381)
		(layer "F.Cu")
		(net "GND")
	)
	(segment
		(start 295.72204 -367.757202)
		(end 295.72204 -368.407442)
		(width 0.381)
		(layer "F.Cu")
		(net "GND")
	)
	(segment
		(start 348.772734 -233.87812)
		(end 348.77248 -233.877866)
		(width 0.2032)
		(layer "F.Cu")
		(net "GND")
	)
	(segment
		(start 43.390566 -433.750212)
		(end 42.298366 -433.750212)
		(width 0.3556)
		(layer "F.Cu")
		(net "GND")
	)
	(segment
		(start 184.439814 -228.766624)
		(end 185.544714 -228.766624)
		(width 0.381)
		(layer "F.Cu")
		(net "GND")
	)
	(segment
		(start 297.899582 -241.516662)
		(end 299.004482 -241.516662)
		(width 0.381)
		(layer "F.Cu")
		(net "GND")
	)
	(segment
		(start 256.080514 -261.916672)
		(end 257.185414 -261.916672)
		(width 0.381)
		(layer "F.Cu")
		(net "GND")
	)
	(segment
		(start 385.064762 -282.683966)
		(end 385.064762 -283.219144)
		(width 0.254)
		(layer "F.Cu")
		(net "GND")
	)
	(segment
		(start 463.659982 -222.816674)
		(end 464.764882 -222.816674)
		(width 0.381)
		(layer "F.Cu")
		(net "GND")
	)
	(segment
		(start 22.147022 -8.320024)
		(end 22.147022 -9.424924)
		(width 0.3556)
		(layer "F.Cu")
		(net "GND")
	)
	(segment
		(start 157.708346 -244.916706)
		(end 158.813246 -244.916706)
		(width 0.381)
		(layer "F.Cu")
		(net "GND")
	)
	(segment
		(start 370.968016 -281.591766)
		(end 370.968016 -281.59202)
		(width 0.254)
		(layer "F.Cu")
		(net "GND")
	)
	(segment
		(start 11.135614 -305.266598)
		(end 12.240514 -305.266598)
		(width 0.381)
		(layer "F.Cu")
		(net "GND")
	)
	(segment
		(start 332.796134 -227.367084)
		(end 332.79588 -226.831144)
		(width 0.2032)
		(layer "F.Cu")
		(net "GND")
	)
	(segment
		(start 91.904312 -233.064304)
		(end 91.904312 -232.528364)
		(width 0.2032)
		(layer "F.Cu")
		(net "GND")
	)
	(segment
		(start 45.859446 -240.666778)
		(end 46.964346 -240.666778)
		(width 0.381)
		(layer "F.Cu")
		(net "GND")
	)
	(segment
		(start 112.580166 -220.041724)
		(end 112.580166 -219.506038)
		(width 0.254)
		(layer "F.Cu")
		(net "GND")
	)
	(segment
		(start 464.764882 -278.916638)
		(end 463.659982 -278.916638)
		(width 0.381)
		(layer "F.Cu")
		(net "GND")
	)
	(segment
		(start 115.869466 -220.855794)
		(end 115.869466 -220.319854)
		(width 0.2032)
		(layer "F.Cu")
		(net "GND")
	)
	(segment
		(start 130.076448 -272.103342)
		(end 130.076194 -272.639282)
		(width 0.2032)
		(layer "F.Cu")
		(net "GND")
	)
	(segment
		(start 65.047114 -239.81664)
		(end 66.152014 -239.81664)
		(width 0.381)
		(layer "F.Cu")
		(net "GND")
	)
	(segment
		(start 286.255714 -260.21665)
		(end 287.360614 -260.21665)
		(width 0.381)
		(layer "F.Cu")
		(net "GND")
	)
	(segment
		(start 428.279814 -251.716794)
		(end 429.384714 -251.716794)
		(width 0.381)
		(layer "F.Cu")
		(net "GND")
	)
	(segment
		(start 51.072034 -358.691942)
		(end 50.362104 -358.691942)
		(width 0.381)
		(layer "F.Cu")
		(net "GND")
	)
	(segment
		(start 129.026412 -233.877866)
		(end 129.026412 -233.34218)
		(width 0.2032)
		(layer "F.Cu")
		(net "GND")
	)
	(segment
		(start 53.403246 -199.01662)
		(end 54.508146 -199.01662)
		(width 0.381)
		(layer "F.Cu")
		(net "GND")
	)
	(segment
		(start 261.285482 -205.816708)
		(end 260.180582 -205.816708)
		(width 0.381)
		(layer "F.Cu")
		(net "GND")
	)
	(segment
		(start 370.615718 -413.50438)
		(end 369.373658 -413.50438)
		(width 0.3556)
		(layer "F.Cu")
		(net "GND")
	)
	(segment
		(start 151.18588 -35.794188)
		(end 151.73325 -36.341558)
		(width 0.3556)
		(layer "F.Cu")
		(net "GND")
	)
	(segment
		(start 462.555082 -241.516662)
		(end 463.659982 -241.516662)
		(width 0.381)
		(layer "F.Cu")
		(net "GND")
	)
	(segment
		(start 363.809534 -233.87812)
		(end 363.80928 -233.877866)
		(width 0.2032)
		(layer "F.Cu")
		(net "GND")
	)
	(segment
		(start 369.44808 -240.388902)
		(end 369.44808 -239.853216)
		(width 0.2032)
		(layer "F.Cu")
		(net "GND")
	)
	(segment
		(start 356.76078 -234.69219)
		(end 356.761034 -234.691936)
		(width 0.2032)
		(layer "F.Cu")
		(net "GND")
	)
	(segment
		(start 277.607014 -283.166566)
		(end 278.711914 -283.166566)
		(width 0.381)
		(layer "F.Cu")
		(net "GND")
	)
	(segment
		(start 178.1556 -118.575328)
		(end 177.75555 -118.975378)
		(width 0.3556)
		(layer "F.Cu")
		(net "GND")
	)
	(segment
		(start 158.813246 -251.716794)
		(end 159.918146 -251.716794)
		(width 0.381)
		(layer "F.Cu")
		(net "GND")
	)
	(segment
		(start 349.712534 -250.155964)
		(end 349.71228 -250.15571)
		(width 0.2032)
		(layer "F.Cu")
		(net "GND")
	)
	(segment
		(start 122.558048 -254.197612)
		(end 122.558048 -254.733298)
		(width 0.254)
		(layer "F.Cu")
		(net "GND")
	)
	(segment
		(start 290.355782 -314.616592)
		(end 291.460682 -314.616592)
		(width 0.381)
		(layer "F.Cu")
		(net "GND")
	)
	(segment
		(start 42.415714 -198.166736)
		(end 41.310814 -198.166736)
		(width 0.381)
		(layer "F.Cu")
		(net "GND")
	)
	(segment
		(start 335.699608 -50.450496)
		(end 336.099658 -50.050446)
		(width 0.2032)
		(layer "F.Cu")
		(net "GND")
	)
	(segment
		(start 214.615014 -241.516662)
		(end 215.719914 -241.516662)
		(width 0.381)
		(layer "F.Cu")
		(net "GND")
	)
	(segment
		(start 384.485134 -215.972644)
		(end 384.485134 -215.436958)
		(width 0.254)
		(layer "F.Cu")
		(net "GND")
	)
	(segment
		(start 170.457114 -235.566712)
		(end 171.827952 -235.566712)
		(width 0.381)
		(layer "F.Cu")
		(net "GND")
	)
	(segment
		(start 371.32768 -245.272306)
		(end 371.32768 -244.73662)
		(width 0.2032)
		(layer "F.Cu")
		(net "GND")
	)
	(segment
		(start 86.845648 -257.45313)
		(end 87.785194 -257.98907)
		(width 0.254)
		(layer "F.Cu")
		(net "GND")
	)
	(segment
		(start 339.014562 -272.917158)
		(end 339.014562 -273.452844)
		(width 0.2032)
		(layer "F.Cu")
		(net "GND")
	)
	(segment
		(start 250.126754 -87.610696)
		(end 250.126754 -89.669112)
		(width 0.3556)
		(layer "F.Cu")
		(net "GND")
	)
	(segment
		(start 275.268182 -213.46668)
		(end 274.163282 -213.46668)
		(width 0.381)
		(layer "F.Cu")
		(net "GND")
	)
	(segment
		(start 23.228046 -204.96657)
		(end 24.332946 -204.96657)
		(width 0.381)
		(layer "F.Cu")
		(net "GND")
	)
	(segment
		(start 208.176114 -316.316614)
		(end 209.281014 -316.316614)
		(width 0.381)
		(layer "F.Cu")
		(net "GND")
	)
	(segment
		(start 342.773762 -266.405868)
		(end 342.774016 -266.406122)
		(width 0.2032)
		(layer "F.Cu")
		(net "GND")
	)
	(segment
		(start 196.532246 -313.766708)
		(end 195.427346 -313.766708)
		(width 0.381)
		(layer "F.Cu")
		(net "GND")
	)
	(segment
		(start 135.714994 -269.38351)
		(end 135.714994 -268.84757)
		(width 0.254)
		(layer "F.Cu")
		(net "GND")
	)
	(segment
		(start 380.25578 -230.900478)
		(end 380.25578 -231.436418)
		(width 0.2032)
		(layer "F.Cu")
		(net "GND")
	)
	(segment
		(start 179.105814 -204.116686)
		(end 178.000914 -204.116686)
		(width 0.381)
		(layer "F.Cu")
		(net "GND")
	)
	(segment
		(start 166.357046 -281.466798)
		(end 165.252146 -281.466798)
		(width 0.381)
		(layer "F.Cu")
		(net "GND")
	)
	(segment
		(start 132.315712 -239.57534)
		(end 132.315966 -239.575086)
		(width 0.2032)
		(layer "F.Cu")
		(net "GND")
	)
	(segment
		(start 286.255714 -250.016772)
		(end 287.360614 -250.016772)
		(width 0.381)
		(layer "F.Cu")
		(net "GND")
	)
	(segment
		(start 130.906012 -245.272306)
		(end 130.906012 -244.73662)
		(width 0.2032)
		(layer "F.Cu")
		(net "GND")
	)
	(segment
		(start 358.280716 -277.522178)
		(end 358.280462 -277.522432)
		(width 0.254)
		(layer "F.Cu")
		(net "GND")
	)
	(segment
		(start 428.279814 -225.36658)
		(end 429.384714 -225.36658)
		(width 0.381)
		(layer "F.Cu")
		(net "GND")
	)
	(segment
		(start 126.317248 -279.150064)
		(end 126.316994 -279.150318)
		(width 0.254)
		(layer "F.Cu")
		(net "GND")
	)
	(segment
		(start 325.525384 -342.591644)
		(end 325.525384 -343.054432)
		(width 0.2032)
		(layer "F.Cu")
		(net "GND")
	)
	(segment
		(start 178.000914 -239.81664)
		(end 179.105814 -239.81664)
		(width 0.381)
		(layer "F.Cu")
		(net "GND")
	)
	(segment
		(start 157.708346 -278.066754)
		(end 158.813246 -278.066754)
		(width 0.381)
		(layer "F.Cu")
		(net "GND")
	)
	(segment
		(start 343.243916 -257.45313)
		(end 343.243916 -257.988816)
		(width 0.2032)
		(layer "F.Cu")
		(net "GND")
	)
	(segment
		(start 115.399312 -229.808786)
		(end 115.399566 -229.808532)
		(width 0.2032)
		(layer "F.Cu")
		(net "GND")
	)
	(segment
		(start 120.098312 -216.78646)
		(end 120.098312 -216.250774)
		(width 0.254)
		(layer "F.Cu")
		(net "GND")
	)
	(segment
		(start 38.315646 -216.016586)
		(end 37.210746 -216.016586)
		(width 0.381)
		(layer "F.Cu")
		(net "GND")
	)
	(segment
		(start 185.544714 -305.266598)
		(end 184.439814 -305.266598)
		(width 0.381)
		(layer "F.Cu")
		(net "GND")
	)
	(segment
		(start 353.581462 -283.498036)
		(end 353.581462 -284.033722)
		(width 0.254)
		(layer "F.Cu")
		(net "GND")
	)
	(segment
		(start 11.135614 -286.56661)
		(end 12.240514 -286.56661)
		(width 0.381)
		(layer "F.Cu")
		(net "GND")
	)
	(segment
		(start 58.688986 -221.255336)
		(end 58.550302 -221.116652)
		(width 0.381)
		(layer "F.Cu")
		(net "GND")
	)
	(segment
		(start 347.472762 -276.172676)
		(end 347.472762 -276.708362)
		(width 0.2032)
		(layer "F.Cu")
		(net "GND")
	)
	(segment
		(start 382.245362 -253.383796)
		(end 382.245362 -253.919482)
		(width 0.2032)
		(layer "F.Cu")
		(net "GND")
	)
	(segment
		(start 290.355782 -196.466714)
		(end 289.250882 -196.466714)
		(width 0.381)
		(layer "F.Cu")
		(net "GND")
	)
	(segment
		(start 122.917966 -236.319568)
		(end 122.917966 -235.783882)
		(width 0.2032)
		(layer "F.Cu")
		(net "GND")
	)
	(segment
		(start 97.653094 -271.289272)
		(end 97.653094 -271.825212)
		(width 0.2032)
		(layer "F.Cu")
		(net "GND")
	)
	(segment
		(start 439.923682 -207.51673)
		(end 441.028582 -207.51673)
		(width 0.381)
		(layer "F.Cu")
		(net "GND")
	)
	(segment
		(start 85.715602 -337.173316)
		(end 85.715602 -336.741008)
		(width 0.2032)
		(layer "F.Cu")
		(net "GND")
	)
	(segment
		(start 210.514946 -234.716574)
		(end 211.619846 -234.716574)
		(width 0.381)
		(layer "F.Cu")
		(net "GND")
	)
	(segment
		(start 171.562014 -286.56661)
		(end 170.457114 -286.56661)
		(width 0.381)
		(layer "F.Cu")
		(net "GND")
	)
	(segment
		(start 292.694614 -281.466798)
		(end 293.799514 -281.466798)
		(width 0.381)
		(layer "F.Cu")
		(net "GND")
	)
	(segment
		(start 312.987182 -316.316614)
		(end 314.092082 -316.316614)
		(width 0.381)
		(layer "F.Cu")
		(net "GND")
	)
	(segment
		(start 448.572382 -224.516696)
		(end 447.467482 -224.516696)
		(width 0.381)
		(layer "F.Cu")
		(net "GND")
	)
	(segment
		(start 87.675466 -238.761524)
		(end 87.675466 -238.225584)
		(width 0.254)
		(layer "F.Cu")
		(net "GND")
	)
	(segment
		(start 110.340648 -280.242264)
		(end 110.340648 -280.77795)
		(width 0.254)
		(layer "F.Cu")
		(net "GND")
	)
	(segment
		(start 287.2994 -343.760044)
		(end 287.2994 -344.700352)
		(width 0.508)
		(layer "F.Cu")
		(net "GND")
	)
	(segment
		(start 49.959514 -306.96662)
		(end 51.064414 -306.96662)
		(width 0.381)
		(layer "F.Cu")
		(net "GND")
	)
	(segment
		(start 101.89845 -92.222574)
		(end 102.53345 -92.222574)
		(width 0.3556)
		(layer "F.Cu")
		(net "GND")
	)
	(segment
		(start 370.967762 -256.807462)
		(end 370.968016 -257.175254)
		(width 0.2032)
		(layer "F.Cu")
		(net "GND")
	)
	(segment
		(start 94.364048 -268.84757)
		(end 94.364048 -269.383256)
		(width 0.2032)
		(layer "F.Cu")
		(net "GND")
	)
	(segment
		(start 111.170212 -233.877866)
		(end 111.170212 -233.34218)
		(width 0.2032)
		(layer "F.Cu")
		(net "GND")
	)
	(segment
		(start 297.899582 -277.216616)
		(end 299.004482 -277.216616)
		(width 0.381)
		(layer "F.Cu")
		(net "GND")
	)
	(segment
		(start 324.67423 -20.646898)
		(end 323.72808 -20.646898)
		(width 0.3556)
		(layer "F.Cu")
		(net "GND")
	)
	(segment
		(start 22.123146 -267.016738)
		(end 23.228046 -267.016738)
		(width 0.381)
		(layer "F.Cu")
		(net "GND")
	)
	(segment
		(start 138.534648 -257.45313)
		(end 138.534648 -257.98907)
		(width 0.254)
		(layer "F.Cu")
		(net "GND")
	)
	(segment
		(start 463.659982 -200.716642)
		(end 464.764882 -200.716642)
		(width 0.381)
		(layer "F.Cu")
		(net "GND")
	)
	(segment
		(start 335.14538 -218.414346)
		(end 335.14538 -217.87866)
		(width 0.2032)
		(layer "F.Cu")
		(net "GND")
	)
	(segment
		(start 99.422712 -220.041978)
		(end 99.422966 -220.041724)
		(width 0.254)
		(layer "F.Cu")
		(net "GND")
	)
	(segment
		(start 326.584818 -38.945566)
		(end 326.999854 -39.445946)
		(width 0.2032)
		(layer "F.Cu")
		(net "GND")
	)
	(segment
		(start 196.532246 -214.316564)
		(end 195.427346 -214.316564)
		(width 0.381)
		(layer "F.Cu")
		(net "GND")
	)
	(segment
		(start 208.176114 -297.616626)
		(end 209.281014 -297.616626)
		(width 0.381)
		(layer "F.Cu")
		(net "GND")
	)
	(segment
		(start 136.184894 -266.405868)
		(end 136.184894 -266.941808)
		(width 0.254)
		(layer "F.Cu")
		(net "GND")
	)
	(segment
		(start 301.343314 -307.816758)
		(end 302.448214 -307.816758)
		(width 0.381)
		(layer "F.Cu")
		(net "GND")
	)
	(segment
		(start 191.983614 -303.566576)
		(end 193.088514 -303.566576)
		(width 0.381)
		(layer "F.Cu")
		(net "GND")
	)
	(segment
		(start 407.627074 -368.826034)
		(end 406.524714 -368.826034)
		(width 0.381)
		(layer "F.Cu")
		(net "GND")
	)
	(segment
		(start 14.579346 -267.016738)
		(end 15.684246 -267.016738)
		(width 0.381)
		(layer "F.Cu")
		(net "GND")
	)
	(segment
		(start 339.748876 -43.751246)
		(end 339.209888 -43.751246)
		(width 0.2032)
		(layer "F.Cu")
		(net "GND")
	)
	(segment
		(start 207.071214 -275.516594)
		(end 208.176114 -275.516594)
		(width 0.381)
		(layer "F.Cu")
		(net "GND")
	)
	(segment
		(start 15.684246 -287.416748)
		(end 16.789146 -287.416748)
		(width 0.381)
		(layer "F.Cu")
		(net "GND")
	)
	(segment
		(start 263.624314 -300.166786)
		(end 264.729214 -300.166786)
		(width 0.381)
		(layer "F.Cu")
		(net "GND")
	)
	(segment
		(start 341.135208 -338.619338)
		(end 341.135208 -338.796884)
		(width 0.381)
		(layer "F.Cu")
		(net "GND")
	)
	(segment
		(start 180.339746 -244.916706)
		(end 181.444646 -244.916706)
		(width 0.381)
		(layer "F.Cu")
		(net "GND")
	)
	(segment
		(start 119.268494 -289.195002)
		(end 119.268494 -289.807142)
		(width 0.254)
		(layer "F.Cu")
		(net "GND")
	)
	(segment
		(start 190.093346 -195.616576)
		(end 188.988446 -195.616576)
		(width 0.381)
		(layer "F.Cu")
		(net "GND")
	)
	(segment
		(start 436.928514 -263.616694)
		(end 438.033414 -263.616694)
		(width 0.381)
		(layer "F.Cu")
		(net "GND")
	)
	(segment
		(start 267.724382 -213.46668)
		(end 268.829282 -213.46668)
		(width 0.381)
		(layer "F.Cu")
		(net "GND")
	)
	(segment
		(start 347.003116 -286.7533)
		(end 347.003116 -287.288986)
		(width 0.254)
		(layer "F.Cu")
		(net "GND")
	)
	(segment
		(start 432.379882 -291.666676)
		(end 433.484782 -291.666676)
		(width 0.381)
		(layer "F.Cu")
		(net "GND")
	)
	(segment
		(start 137.124694 -282.683966)
		(end 137.124694 -283.219144)
		(width 0.254)
		(layer "F.Cu")
		(net "GND")
	)
	(segment
		(start 360.51998 -222.76181)
		(end 360.520234 -222.761556)
		(width 0.254)
		(layer "F.Cu")
		(net "GND")
	)
	(segment
		(start 86.437216 -337.601306)
		(end 86.143592 -337.601306)
		(width 0.2032)
		(layer "F.Cu")
		(net "GND")
	)
	(segment
		(start 60.947046 -260.21665)
		(end 62.051946 -260.21665)
		(width 0.381)
		(layer "F.Cu")
		(net "GND")
	)
	(segment
		(start 286.255714 -306.116736)
		(end 287.360614 -306.116736)
		(width 0.381)
		(layer "F.Cu")
		(net "GND")
	)
	(segment
		(start 420.548308 -166.099236)
		(end 420.124128 -166.099236)
		(width 0.381)
		(layer "F.Cu")
		(net "GND")
	)
	(segment
		(start 419.502082 -198.166736)
		(end 418.397182 -198.166736)
		(width 0.381)
		(layer "F.Cu")
		(net "GND")
	)
	(segment
		(start 368.508534 -230.622602)
		(end 368.50828 -230.622348)
		(width 0.2032)
		(layer "F.Cu")
		(net "GND")
	)
	(segment
		(start 49.493932 -173.824392)
		(end 49.529238 -173.789086)
		(width 0.254)
		(layer "F.Cu")
		(net "GND")
	)
	(segment
		(start 433.484782 -221.116652)
		(end 434.589682 -221.116652)
		(width 0.381)
		(layer "F.Cu")
		(net "GND")
	)
	(segment
		(start 37.330634 -107.539282)
		(end 37.940234 -107.539282)
		(width 0.3556)
		(layer "F.Cu")
		(net "GND")
	)
	(segment
		(start 100.362512 -242.295172)
		(end 100.362766 -242.294918)
		(width 0.254)
		(layer "F.Cu")
		(net "GND")
	)
	(segment
		(start 39.420546 -281.466798)
		(end 38.315646 -281.466798)
		(width 0.381)
		(layer "F.Cu")
		(net "GND")
	)
	(segment
		(start 170.457114 -194.766692)
		(end 171.562014 -194.766692)
		(width 0.381)
		(layer "F.Cu")
		(net "GND")
	)
	(segment
		(start 110.340648 -267.755624)
		(end 110.340394 -267.755878)
		(width 0.254)
		(layer "F.Cu")
		(net "GND")
	)
	(segment
		(start 355.42855 -401.955)
		(end 354.7364 -401.955)
		(width 0.3556)
		(layer "F.Cu")
		(net "GND")
	)
	(segment
		(start 126.786894 -264.778236)
		(end 126.786894 -265.314176)
		(width 0.2032)
		(layer "F.Cu")
		(net "GND")
	)
	(segment
		(start 367.678716 -265.592306)
		(end 367.678716 -266.127992)
		(width 0.2032)
		(layer "F.Cu")
		(net "GND")
	)
	(segment
		(start 266.619482 -215.166702)
		(end 267.724382 -215.166702)
		(width 0.381)
		(layer "F.Cu")
		(net "GND")
	)
	(segment
		(start 210.143852 -126.51105)
		(end 210.14563 -126.512828)
		(width 0.3556)
		(layer "F.Cu")
		(net "GND")
	)
	(segment
		(start 441.028582 -245.76659)
		(end 442.133482 -245.76659)
		(width 0.381)
		(layer "F.Cu")
		(net "GND")
	)
	(segment
		(start 353.581716 -278.614378)
		(end 353.581716 -279.150318)
		(width 0.254)
		(layer "F.Cu")
		(net "GND")
	)
	(segment
		(start 342.90254 -39.295324)
		(end 343.403174 -39.443152)
		(width 0.2032)
		(layer "F.Cu")
		(net "GND")
	)
	(segment
		(start 87.315294 -269.66164)
		(end 87.315294 -270.19758)
		(width 0.254)
		(layer "F.Cu")
		(net "GND")
	)
	(segment
		(start 15.684246 -212.616796)
		(end 16.789146 -212.616796)
		(width 0.381)
		(layer "F.Cu")
		(net "GND")
	)
	(segment
		(start 443.367414 -214.316564)
		(end 444.472314 -214.316564)
		(width 0.381)
		(layer "F.Cu")
		(net "GND")
	)
	(segment
		(start 49.896522 -436.803038)
		(end 49.896522 -437.438038)
		(width 0.3556)
		(layer "F.Cu")
		(net "GND")
	)
	(segment
		(start 337.02498 -215.158574)
		(end 337.02498 -214.622888)
		(width 0.2032)
		(layer "F.Cu")
		(net "GND")
	)
	(segment
		(start 308.887114 -234.716574)
		(end 309.992014 -234.716574)
		(width 0.381)
		(layer "F.Cu")
		(net "GND")
	)
	(segment
		(start 106.581448 -272.103342)
		(end 106.581448 -272.639028)
		(width 0.2032)
		(layer "F.Cu")
		(net "GND")
	)
	(segment
		(start 285.150814 -220.266768)
		(end 286.255714 -220.266768)
		(width 0.381)
		(layer "F.Cu")
		(net "GND")
	)
	(segment
		(start 192.63868 -114.041428)
		(end 192.63868 -113.706148)
		(width 0.3556)
		(layer "F.Cu")
		(net "GND")
	)
	(segment
		(start 207.071214 -282.316682)
		(end 208.176114 -282.316682)
		(width 0.381)
		(layer "F.Cu")
		(net "GND")
	)
	(segment
		(start 30.771846 -300.166786)
		(end 31.876746 -300.166786)
		(width 0.381)
		(layer "F.Cu")
		(net "GND")
	)
	(segment
		(start 360.050334 -238.761524)
		(end 360.05008 -238.76127)
		(width 0.254)
		(layer "F.Cu")
		(net "GND")
	)
	(segment
		(start 304.122582 -312.91657)
		(end 305.443382 -312.91657)
		(width 0.381)
		(layer "F.Cu")
		(net "GND")
	)
	(segment
		(start 370.498116 -261.244588)
		(end 370.497862 -261.244842)
		(width 0.2032)
		(layer "F.Cu")
		(net "GND")
	)
	(segment
		(start 131.846066 -235.506006)
		(end 131.846066 -234.970066)
		(width 0.2032)
		(layer "F.Cu")
		(net "GND")
	)
	(segment
		(start 85.325712 -218.414346)
		(end 85.324696 -218.41333)
		(width 0.2032)
		(layer "F.Cu")
		(net "GND")
	)
	(segment
		(start 110.700566 -229.808786)
		(end 110.700566 -229.272846)
		(width 0.2032)
		(layer "F.Cu")
		(net "GND")
	)
	(segment
		(start 129.026666 -237.133892)
		(end 129.026666 -236.597952)
		(width 0.2032)
		(layer "F.Cu")
		(net "GND")
	)
	(segment
		(start 33.010348 -390.10717)
		(end 32.350964 -390.10717)
		(width 0.4572)
		(layer "F.Cu")
		(net "GND")
	)
	(segment
		(start 7.035546 -285.716726)
		(end 8.140446 -285.716726)
		(width 0.381)
		(layer "F.Cu")
		(net "GND")
	)
	(segment
		(start 433.484782 -235.566712)
		(end 434.589682 -235.566712)
		(width 0.381)
		(layer "F.Cu")
		(net "GND")
	)
	(segment
		(start 382.245362 -269.66164)
		(end 382.245616 -270.167862)
		(width 0.2032)
		(layer "F.Cu")
		(net "GND")
	)
	(segment
		(start 48.854614 -221.116652)
		(end 49.959514 -221.116652)
		(width 0.381)
		(layer "F.Cu")
		(net "GND")
	)
	(segment
		(start 195.427346 -251.716794)
		(end 196.532246 -251.716794)
		(width 0.381)
		(layer "F.Cu")
		(net "GND")
	)
	(segment
		(start 29.666946 -290.816792)
		(end 30.771846 -290.816792)
		(width 0.381)
		(layer "F.Cu")
		(net "GND")
	)
	(segment
		(start 9.245346 -273.816572)
		(end 8.140446 -273.816572)
		(width 0.381)
		(layer "F.Cu")
		(net "GND")
	)
	(segment
		(start 405.648414 -296.766742)
		(end 406.753314 -296.766742)
		(width 0.381)
		(layer "F.Cu")
		(net "GND")
	)
	(segment
		(start 124.907294 -281.05608)
		(end 124.907294 -281.591512)
		(width 0.254)
		(layer "F.Cu")
		(net "GND")
	)
	(segment
		(start 433.484782 -269.566644)
		(end 434.589682 -269.566644)
		(width 0.381)
		(layer "F.Cu")
		(net "GND")
	)
	(segment
		(start 345.593162 -258.802886)
		(end 345.593416 -258.80314)
		(width 0.2032)
		(layer "F.Cu")
		(net "GND")
	)
	(segment
		(start 372.267734 -242.017042)
		(end 372.26748 -242.016788)
		(width 0.2032)
		(layer "F.Cu")
		(net "GND")
	)
	(segment
		(start 110.700566 -226.017328)
		(end 110.700566 -226.553268)
		(width 0.254)
		(layer "F.Cu")
		(net "GND")
	)
	(segment
		(start 385.424934 -230.622602)
		(end 384.955034 -230.900478)
		(width 0.254)
		(layer "F.Cu")
		(net "GND")
	)
	(segment
		(start 407.858214 -304.416714)
		(end 406.753314 -304.416714)
		(width 0.381)
		(layer "F.Cu")
		(net "GND")
	)
	(segment
		(start 210.514946 -250.016772)
		(end 211.619846 -250.016772)
		(width 0.381)
		(layer "F.Cu")
		(net "GND")
	)
	(segment
		(start 159.918146 -273.816572)
		(end 158.813246 -273.816572)
		(width 0.381)
		(layer "F.Cu")
		(net "GND")
	)
	(segment
		(start 278.711914 -311.216802)
		(end 279.816814 -311.216802)
		(width 0.381)
		(layer "F.Cu")
		(net "GND")
	)
	(segment
		(start 325.605902 -20.148296)
		(end 324.873112 -20.148296)
		(width 0.3556)
		(layer "F.Cu")
		(net "GND")
	)
	(segment
		(start 116.919248 -280.242264)
		(end 116.919248 -280.778204)
		(width 0.254)
		(layer "F.Cu")
		(net "GND")
	)
	(segment
		(start 348.882462 -265.592306)
		(end 348.882462 -266.128246)
		(width 0.254)
		(layer "F.Cu")
		(net "GND")
	)
	(segment
		(start 203.598018 -129.466848)
		(end 203.598018 -130.287268)
		(width 0.3556)
		(layer "F.Cu")
		(net "GND")
	)
	(segment
		(start 132.315712 -244.458744)
		(end 132.315966 -244.45849)
		(width 0.2032)
		(layer "F.Cu")
		(net "GND")
	)
	(segment
		(start 444.775336 -47.627286)
		(end 444.775336 -48.495712)
		(width 0.3556)
		(layer "F.Cu")
		(net "GND")
	)
	(segment
		(start 344.183716 -268.84757)
		(end 344.183716 -269.383256)
		(width 0.2032)
		(layer "F.Cu")
		(net "GND")
	)
	(segment
		(start 99.532948 -269.661894)
		(end 99.532948 -270.19758)
		(width 0.2032)
		(layer "F.Cu")
		(net "GND")
	)
	(segment
		(start 122.917712 -229.808786)
		(end 122.917712 -229.272846)
		(width 0.254)
		(layer "F.Cu")
		(net "GND")
	)
	(segment
		(start 414.297114 -244.916706)
		(end 415.402014 -244.916706)
		(width 0.381)
		(layer "F.Cu")
		(net "GND")
	)
	(segment
		(start 378.016516 -283.497782)
		(end 378.016516 -284.033468)
		(width 0.254)
		(layer "F.Cu")
		(net "GND")
	)
	(segment
		(start 43.520614 -266.1666)
		(end 42.415714 -266.1666)
		(width 0.381)
		(layer "F.Cu")
		(net "GND")
	)
	(segment
		(start 86.265766 -226.553268)
		(end 86.265766 -226.017328)
		(width 0.2032)
		(layer "F.Cu")
		(net "GND")
	)
	(segment
		(start 94.723712 -244.458744)
		(end 94.723712 -243.922804)
		(width 0.2032)
		(layer "F.Cu")
		(net "GND")
	)
	(segment
		(start 333.89824 -57.605168)
		(end 332.897734 -57.605168)
		(width 0.2032)
		(layer "F.Cu")
		(net "GND")
	)
	(segment
		(start 349.352616 -256.639568)
		(end 349.352616 -257.175254)
		(width 0.2032)
		(layer "F.Cu")
		(net "GND")
	)
	(segment
		(start 115.979448 -278.614378)
		(end 115.979448 -279.150064)
		(width 0.254)
		(layer "F.Cu")
		(net "GND")
	)
	(segment
		(start 349.24238 -239.57534)
		(end 349.24238 -239.0394)
		(width 0.2032)
		(layer "F.Cu")
		(net "GND")
	)
	(segment
		(start 104.231694 -279.428194)
		(end 104.231694 -279.96388)
		(width 0.2032)
		(layer "F.Cu")
		(net "GND")
	)
	(segment
		(start 344.183716 -261.244588)
		(end 344.183462 -261.244842)
		(width 0.2032)
		(layer "F.Cu")
		(net "GND")
	)
	(segment
		(start 88.615012 -235.505752)
		(end 88.615012 -234.970066)
		(width 0.2032)
		(layer "F.Cu")
		(net "GND")
	)
	(segment
		(start 213.369398 -21.06676)
		(end 213.369398 -20.687792)
		(width 0.3556)
		(layer "F.Cu")
		(net "GND")
	)
	(segment
		(start 127.616712 -249.342148)
		(end 127.616966 -249.341894)
		(width 0.2032)
		(layer "F.Cu")
		(net "GND")
	)
	(segment
		(start 456.116182 -301.01667)
		(end 455.011282 -301.01667)
		(width 0.381)
		(layer "F.Cu")
		(net "GND")
	)
	(segment
		(start 277.607014 -234.716574)
		(end 278.711914 -234.716574)
		(width 0.381)
		(layer "F.Cu")
		(net "GND")
	)
	(segment
		(start 350.762316 -283.497782)
		(end 350.762316 -284.033468)
		(width 0.254)
		(layer "F.Cu")
		(net "GND")
	)
	(segment
		(start 406.753314 -238.966756)
		(end 408.157426 -238.966756)
		(width 0.381)
		(layer "F.Cu")
		(net "GND")
	)
	(segment
		(start 119.079264 -335.541112)
		(end 118.79961 -335.541112)
		(width 0.1778)
		(layer "F.Cu")
		(net "GND")
	)
	(segment
		(start 125.847094 -272.917158)
		(end 125.847348 -273.453098)
		(width 0.2032)
		(layer "F.Cu")
		(net "GND")
	)
	(segment
		(start 118.798848 -284.033468)
		(end 118.798594 -284.033722)
		(width 0.254)
		(layer "F.Cu")
		(net "GND")
	)
	(segment
		(start 448.572382 -213.46668)
		(end 447.467482 -213.46668)
		(width 0.381)
		(layer "F.Cu")
		(net "GND")
	)
	(segment
		(start 199.527414 -278.916638)
		(end 200.632314 -278.916638)
		(width 0.381)
		(layer "F.Cu")
		(net "GND")
	)
	(segment
		(start 65.047114 -277.216616)
		(end 66.152014 -277.216616)
		(width 0.381)
		(layer "F.Cu")
		(net "GND")
	)
	(segment
		(start 131.016248 -254.733298)
		(end 131.015994 -254.733552)
		(width 0.254)
		(layer "F.Cu")
		(net "GND")
	)
	(segment
		(start 360.050334 -220.855794)
		(end 360.050334 -220.319854)
		(width 0.2032)
		(layer "F.Cu")
		(net "GND")
	)
	(segment
		(start 345.48318 -222.76181)
		(end 345.483434 -222.761556)
		(width 0.254)
		(layer "F.Cu")
		(net "GND")
	)
	(segment
		(start 90.964512 -230.900478)
		(end 90.964512 -231.436418)
		(width 0.2032)
		(layer "F.Cu")
		(net "GND")
	)
	(segment
		(start 262.519414 -217.716608)
		(end 263.624314 -217.716608)
		(width 0.381)
		(layer "F.Cu")
		(net "GND")
	)
	(segment
		(start 436.928514 -197.316598)
		(end 438.033414 -197.316598)
		(width 0.381)
		(layer "F.Cu")
		(net "GND")
	)
	(segment
		(start 196.532246 -279.766776)
		(end 195.427346 -279.766776)
		(width 0.381)
		(layer "F.Cu")
		(net "GND")
	)
	(segment
		(start 204.003148 -103.765096)
		(end 204.0001 -103.762048)
		(width 0.3556)
		(layer "F.Cu")
		(net "GND")
	)
	(segment
		(start 20.889214 -205.816708)
		(end 19.784314 -205.816708)
		(width 0.381)
		(layer "F.Cu")
		(net "GND")
	)
	(segment
		(start 134.305294 -261.522718)
		(end 134.305294 -262.058404)
		(width 0.2032)
		(layer "F.Cu")
		(net "GND")
	)
	(segment
		(start 113.629694 -258.80314)
		(end 113.629948 -258.803394)
		(width 0.254)
		(layer "F.Cu")
		(net "GND")
	)
	(segment
		(start 360.05008 -235.505752)
		(end 360.05008 -234.970066)
		(width 0.2032)
		(layer "F.Cu")
		(net "GND")
	)
	(segment
		(start 95.663512 -220.041978)
		(end 95.663766 -220.041724)
		(width 0.254)
		(layer "F.Cu")
		(net "GND")
	)
	(segment
		(start 22.123146 -276.366732)
		(end 23.228046 -276.366732)
		(width 0.381)
		(layer "F.Cu")
		(net "GND")
	)
	(segment
		(start 30.771846 -285.716726)
		(end 31.876746 -285.716726)
		(width 0.381)
		(layer "F.Cu")
		(net "GND")
	)
	(segment
		(start 57.503314 -284.866588)
		(end 58.608214 -284.866588)
		(width 0.381)
		(layer "F.Cu")
		(net "GND")
	)
	(segment
		(start 421.840914 -251.716794)
		(end 422.945814 -251.716794)
		(width 0.381)
		(layer "F.Cu")
		(net "GND")
	)
	(segment
		(start 429.384714 -268.71676)
		(end 430.489614 -268.71676)
		(width 0.381)
		(layer "F.Cu")
		(net "GND")
	)
	(segment
		(start 305.69154 -427.168818)
		(end 305.08194 -427.168818)
		(width 0.3556)
		(layer "F.Cu")
		(net "GND")
	)
	(segment
		(start 379.31598 -222.76181)
		(end 379.316234 -222.761556)
		(width 0.254)
		(layer "F.Cu")
		(net "GND")
	)
	(segment
		(start 124.327666 -243.644928)
		(end 124.327412 -243.644674)
		(width 0.2032)
		(layer "F.Cu")
		(net "GND")
	)
	(segment
		(start 449.677282 -244.066568)
		(end 448.572382 -244.066568)
		(width 0.381)
		(layer "F.Cu")
		(net "GND")
	)
	(segment
		(start 358.280716 -281.869896)
		(end 358.280716 -282.405582)
		(width 0.254)
		(layer "F.Cu")
		(net "GND")
	)
	(segment
		(start 104.231694 -266.405868)
		(end 104.231694 -266.941808)
		(width 0.254)
		(layer "F.Cu")
		(net "GND")
	)
	(segment
		(start 23.946866 -8.320024)
		(end 23.946866 -9.424924)
		(width 0.3556)
		(layer "F.Cu")
		(net "GND")
	)
	(segment
		(start 465.144358 -39.75608)
		(end 464.509358 -39.75608)
		(width 0.3556)
		(layer "F.Cu")
		(net "GND")
	)
	(segment
		(start 463.659982 -289.966654)
		(end 462.555082 -289.966654)
		(width 0.381)
		(layer "F.Cu")
		(net "GND")
	)
	(segment
		(start 445.577214 -204.96657)
		(end 444.472314 -204.96657)
		(width 0.381)
		(layer "F.Cu")
		(net "GND")
	)
	(segment
		(start 94.40926 -414.42894)
		(end 93.556074 -413.575754)
		(width 0.3556)
		(layer "F.Cu")
		(net "GND")
	)
	(segment
		(start 432.822858 -176.61382)
		(end 432.81473 -176.61382)
		(width 0.254)
		(layer "F.Cu")
		(net "GND")
	)
	(segment
		(start 181.444646 -212.616796)
		(end 182.549546 -212.616796)
		(width 0.381)
		(layer "F.Cu")
		(net "GND")
	)
	(segment
		(start 202.971146 -268.71676)
		(end 204.076046 -268.71676)
		(width 0.381)
		(layer "F.Cu")
		(net "GND")
	)
	(segment
		(start 143.637 -36.894008)
		(end 143.76908 -36.761928)
		(width 0.3556)
		(layer "F.Cu")
		(net "GND")
	)
	(segment
		(start 59.702446 -220.266768)
		(end 60.947046 -220.266768)
		(width 0.381)
		(layer "F.Cu")
		(net "GND")
	)
	(segment
		(start 328.395584 -58.020204)
		(end 328.81062 -57.605168)
		(width 0.2032)
		(layer "F.Cu")
		(net "GND")
	)
	(segment
		(start 406.753314 -260.21665)
		(end 407.858214 -260.21665)
		(width 0.381)
		(layer "F.Cu")
		(net "GND")
	)
	(segment
		(start 304.338482 -244.066568)
		(end 305.443382 -244.066568)
		(width 0.381)
		(layer "F.Cu")
		(net "GND")
	)
	(segment
		(start 33.466024 -163.475162)
		(end 34.08807 -163.475162)
		(width 0.381)
		(layer "F.Cu")
		(net "GND")
	)
	(segment
		(start 207.071214 -271.266666)
		(end 208.176114 -271.266666)
		(width 0.381)
		(layer "F.Cu")
		(net "GND")
	)
	(segment
		(start 460.664814 -270.416782)
		(end 459.559914 -270.416782)
		(width 0.381)
		(layer "F.Cu")
		(net "GND")
	)
	(segment
		(start 263.624314 -231.316784)
		(end 264.729214 -231.316784)
		(width 0.381)
		(layer "F.Cu")
		(net "GND")
	)
	(segment
		(start 127.726694 -274.54479)
		(end 127.726948 -275.08073)
		(width 0.2032)
		(layer "F.Cu")
		(net "GND")
	)
	(segment
		(start 366.725454 -334.191102)
		(end 366.297464 -333.763112)
		(width 0.2032)
		(layer "F.Cu")
		(net "GND")
	)
	(segment
		(start 107.521248 -285.6611)
		(end 107.520994 -285.661354)
		(width 0.254)
		(layer "F.Cu")
		(net "GND")
	)
	(segment
		(start 131.956048 -281.869896)
		(end 131.956048 -282.405582)
		(width 0.254)
		(layer "F.Cu")
		(net "GND")
	)
	(segment
		(start 57.503314 -280.61666)
		(end 58.608214 -280.61666)
		(width 0.381)
		(layer "F.Cu")
		(net "GND")
	)
	(segment
		(start 424.836082 -261.066788)
		(end 425.940982 -261.066788)
		(width 0.381)
		(layer "F.Cu")
		(net "GND")
	)
	(segment
		(start 200.632314 -219.41663)
		(end 201.737214 -219.41663)
		(width 0.381)
		(layer "F.Cu")
		(net "GND")
	)
	(segment
		(start 459.559914 -233.016806)
		(end 458.455014 -233.016806)
		(width 0.381)
		(layer "F.Cu")
		(net "GND")
	)
	(segment
		(start 305.443382 -295.916604)
		(end 306.548282 -295.916604)
		(width 0.381)
		(layer "F.Cu")
		(net "GND")
	)
	(segment
		(start 56.398414 -226.216718)
		(end 57.503314 -226.216718)
		(width 0.381)
		(layer "F.Cu")
		(net "GND")
	)
	(segment
		(start 42.415714 -271.266666)
		(end 41.310814 -271.266666)
		(width 0.381)
		(layer "F.Cu")
		(net "GND")
	)
	(segment
		(start 449.677282 -288.266632)
		(end 448.572382 -288.266632)
		(width 0.381)
		(layer "F.Cu")
		(net "GND")
	)
	(segment
		(start 453.121014 -298.466764)
		(end 452.016114 -298.466764)
		(width 0.381)
		(layer "F.Cu")
		(net "GND")
	)
	(segment
		(start 86.375494 -271.289272)
		(end 87.315294 -271.825212)
		(width 0.2032)
		(layer "F.Cu")
		(net "GND")
	)
	(segment
		(start 304.338482 -301.01667)
		(end 305.443382 -301.01667)
		(width 0.381)
		(layer "F.Cu")
		(net "GND")
	)
	(segment
		(start 370.858034 -220.041724)
		(end 370.858034 -219.506038)
		(width 0.254)
		(layer "F.Cu")
		(net "GND")
	)
	(segment
		(start 114.30508 -398.275048)
		(end 114.30508 -398.884648)
		(width 0.381)
		(layer "F.Cu")
		(net "GND")
	)
	(segment
		(start 296.794682 -224.516696)
		(end 297.899582 -224.516696)
		(width 0.381)
		(layer "F.Cu")
		(net "GND")
	)
	(segment
		(start 159.952436 -295.06672)
		(end 159.977582 -295.041574)
		(width 0.381)
		(layer "F.Cu")
		(net "GND")
	)
	(segment
		(start 341.25408 -245.272306)
		(end 341.25408 -244.73662)
		(width 0.2032)
		(layer "F.Cu")
		(net "GND")
	)
	(segment
		(start 204.076046 -276.366732)
		(end 205.180946 -276.366732)
		(width 0.381)
		(layer "F.Cu")
		(net "GND")
	)
	(segment
		(start 378.37618 -219.506292)
		(end 378.376434 -219.506038)
		(width 0.254)
		(layer "F.Cu")
		(net "GND")
	)
	(segment
		(start 34.871914 -303.566576)
		(end 33.767014 -303.566576)
		(width 0.381)
		(layer "F.Cu")
		(net "GND")
	)
	(segment
		(start 452.016114 -233.016806)
		(end 450.911214 -233.016806)
		(width 0.381)
		(layer "F.Cu")
		(net "GND")
	)
	(segment
		(start 340.424516 -284.033468)
		(end 340.424262 -284.033722)
		(width 0.254)
		(layer "F.Cu")
		(net "GND")
	)
	(segment
		(start 181.444646 -220.266768)
		(end 182.549546 -220.266768)
		(width 0.381)
		(layer "F.Cu")
		(net "GND")
	)
	(segment
		(start 91.544648 -255.825498)
		(end 91.544648 -256.361184)
		(width 0.2032)
		(layer "F.Cu")
		(net "GND")
	)
	(segment
		(start 369.558316 -280.242264)
		(end 369.558062 -280.778204)
		(width 0.254)
		(layer "F.Cu")
		(net "GND")
	)
	(segment
		(start 282.811982 -200.716642)
		(end 281.707082 -200.716642)
		(width 0.381)
		(layer "F.Cu")
		(net "GND")
	)
	(segment
		(start 376.49658 -233.064304)
		(end 376.49658 -232.528618)
		(width 0.254)
		(layer "F.Cu")
		(net "GND")
	)
	(segment
		(start 353.581716 -277.521924)
		(end 353.581462 -277.522178)
		(width 0.2032)
		(layer "F.Cu")
		(net "GND")
	)
	(segment
		(start 136.946894 -14.705076)
		(end 136.946894 -13.600176)
		(width 0.3556)
		(layer "F.Cu")
		(net "GND")
	)
	(segment
		(start 169.352214 -261.066788)
		(end 170.457114 -261.066788)
		(width 0.381)
		(layer "F.Cu")
		(net "GND")
	)
	(segment
		(start 18.679414 -226.216718)
		(end 19.784314 -226.216718)
		(width 0.381)
		(layer "F.Cu")
		(net "GND")
	)
	(segment
		(start 166.357046 -214.316564)
		(end 167.461946 -214.316564)
		(width 0.381)
		(layer "F.Cu")
		(net "GND")
	)
	(segment
		(start 457.221082 -264.466578)
		(end 456.116182 -264.466578)
		(width 0.381)
		(layer "F.Cu")
		(net "GND")
	)
	(segment
		(start 60.947046 -315.46673)
		(end 62.051946 -315.46673)
		(width 0.381)
		(layer "F.Cu")
		(net "GND")
	)
	(segment
		(start 195.427346 -225.36658)
		(end 196.532246 -225.36658)
		(width 0.381)
		(layer "F.Cu")
		(net "GND")
	)
	(segment
		(start 373.787162 -272.917158)
		(end 373.787416 -273.453098)
		(width 0.2032)
		(layer "F.Cu")
		(net "GND")
	)
	(segment
		(start 14.579346 -227.066602)
		(end 15.684246 -227.066602)
		(width 0.381)
		(layer "F.Cu")
		(net "GND")
	)
	(segment
		(start 459.559914 -246.616728)
		(end 458.455014 -246.616728)
		(width 0.381)
		(layer "F.Cu")
		(net "GND")
	)
	(segment
		(start 240.522252 -251.755148)
		(end 243.5479 -251.755148)
		(width 0.3556)
		(layer "F.Cu")
		(net "GND")
	)
	(segment
		(start 129.026666 -243.644928)
		(end 129.026412 -243.644674)
		(width 0.2032)
		(layer "F.Cu")
		(net "GND")
	)
	(segment
		(start 30.771846 -276.366732)
		(end 31.876746 -276.366732)
		(width 0.381)
		(layer "F.Cu")
		(net "GND")
	)
	(segment
		(start 43.520614 -232.166668)
		(end 42.415714 -232.166668)
		(width 0.381)
		(layer "F.Cu")
		(net "GND")
	)
	(segment
		(start 38.315646 -217.716608)
		(end 37.210746 -217.716608)
		(width 0.381)
		(layer "F.Cu")
		(net "GND")
	)
	(segment
		(start 263.624314 -258.516628)
		(end 264.729214 -258.516628)
		(width 0.381)
		(layer "F.Cu")
		(net "GND")
	)
	(segment
		(start 171.562014 -280.61666)
		(end 170.457114 -280.61666)
		(width 0.381)
		(layer "F.Cu")
		(net "GND")
	)
	(segment
		(start 180.339746 -216.016586)
		(end 181.444646 -216.016586)
		(width 0.381)
		(layer "F.Cu")
		(net "GND")
	)
	(segment
		(start 368.148616 -282.68422)
		(end 368.148616 -283.219906)
		(width 0.254)
		(layer "F.Cu")
		(net "GND")
	)
	(segment
		(start 130.906266 -214.344758)
		(end 130.906266 -213.732618)
		(width 0.254)
		(layer "F.Cu")
		(net "GND")
	)
	(segment
		(start 366.738916 -283.497782)
		(end 366.738916 -284.033468)
		(width 0.254)
		(layer "F.Cu")
		(net "GND")
	)
	(segment
		(start 281.707082 -216.866724)
		(end 282.811982 -216.866724)
		(width 0.381)
		(layer "F.Cu")
		(net "GND")
	)
	(segment
		(start 115.399312 -220.041978)
		(end 115.399566 -220.041724)
		(width 0.254)
		(layer "F.Cu")
		(net "GND")
	)
	(segment
		(start 131.016248 -257.45313)
		(end 131.015994 -257.98907)
		(width 0.2032)
		(layer "F.Cu")
		(net "GND")
	)
	(segment
		(start 173.900846 -240.666778)
		(end 172.795946 -240.666778)
		(width 0.381)
		(layer "F.Cu")
		(net "GND")
	)
	(segment
		(start 165.455346 -287.416748)
		(end 165.252146 -287.213548)
		(width 0.381)
		(layer "F.Cu")
		(net "GND")
	)
	(segment
		(start 33.767014 -247.466612)
		(end 34.871914 -247.466612)
		(width 0.381)
		(layer "F.Cu")
		(net "GND")
	)
	(segment
		(start 85.325712 -242.830858)
		(end 85.325712 -242.294918)
		(width 0.254)
		(layer "F.Cu")
		(net "GND")
	)
	(segment
		(start 373.317516 -279.150064)
		(end 373.317262 -279.150318)
		(width 0.254)
		(layer "F.Cu")
		(net "GND")
	)
	(segment
		(start 117.278912 -234.69219)
		(end 117.279166 -234.691936)
		(width 0.254)
		(layer "F.Cu")
		(net "GND")
	)
	(segment
		(start 29.666946 -195.616576)
		(end 30.771846 -195.616576)
		(width 0.381)
		(layer "F.Cu")
		(net "GND")
	)
	(segment
		(start 261.285482 -211.766658)
		(end 260.180582 -211.766658)
		(width 0.381)
		(layer "F.Cu")
		(net "GND")
	)
	(segment
		(start 359.110534 -225.203512)
		(end 359.11028 -225.203258)
		(width 0.254)
		(layer "F.Cu")
		(net "GND")
	)
	(segment
		(start 368.148362 -274.54479)
		(end 368.148616 -275.08073)
		(width 0.254)
		(layer "F.Cu")
		(net "GND")
	)
	(segment
		(start 166.357046 -203.266802)
		(end 167.461946 -203.266802)
		(width 0.381)
		(layer "F.Cu")
		(net "GND")
	)
	(segment
		(start 23.228046 -223.666558)
		(end 24.332946 -223.666558)
		(width 0.381)
		(layer "F.Cu")
		(net "GND")
	)
	(segment
		(start 278.711914 -221.96679)
		(end 279.816814 -221.96679)
		(width 0.381)
		(layer "F.Cu")
		(net "GND")
	)
	(segment
		(start 405.496776 -54.743604)
		(end 405.496776 -55.313072)
		(width 0.3556)
		(layer "F.Cu")
		(net "GND")
	)
	(segment
		(start 106.645964 -393.711684)
		(end 107.331764 -393.711684)
		(width 0.3556)
		(layer "F.Cu")
		(net "GND")
	)
	(segment
		(start 131.956048 -286.7533)
		(end 131.956048 -287.288986)
		(width 0.254)
		(layer "F.Cu")
		(net "GND")
	)
	(segment
		(start 88.615266 -250.155964)
		(end 88.615012 -250.15571)
		(width 0.2032)
		(layer "F.Cu")
		(net "GND")
	)
	(segment
		(start 23.228046 -272.116804)
		(end 24.332946 -272.116804)
		(width 0.381)
		(layer "F.Cu")
		(net "GND")
	)
	(segment
		(start 342.190578 -44.221146)
		(end 341.918798 -43.751246)
		(width 0.2032)
		(layer "F.Cu")
		(net "GND")
	)
	(segment
		(start 176.896014 -303.566576)
		(end 178.000914 -303.566576)
		(width 0.381)
		(layer "F.Cu")
		(net "GND")
	)
	(segment
		(start 179.105814 -269.566644)
		(end 178.000914 -269.566644)
		(width 0.381)
		(layer "F.Cu")
		(net "GND")
	)
	(segment
		(start 230.984044 -51.564794)
		(end 230.984298 -51.565048)
		(width 0.381)
		(layer "F.Cu")
		(net "GND")
	)
	(segment
		(start 132.315712 -229.808786)
		(end 132.315966 -229.808532)
		(width 0.2032)
		(layer "F.Cu")
		(net "GND")
	)
	(segment
		(start 204.076046 -281.466798)
		(end 205.180946 -281.466798)
		(width 0.381)
		(layer "F.Cu")
		(net "GND")
	)
	(segment
		(start 194.33413 -352.694748)
		(end 194.33413 -353.761548)
		(width 0.3556)
		(layer "F.Cu")
		(net "GND")
	)
	(segment
		(start 278.711914 -287.416748)
		(end 279.816814 -287.416748)
		(width 0.381)
		(layer "F.Cu")
		(net "GND")
	)
	(segment
		(start 97.543112 -241.203226)
		(end 97.543112 -240.667286)
		(width 0.2032)
		(layer "F.Cu")
		(net "GND")
	)
	(segment
		(start 414.756854 -11.26998)
		(end 414.756854 -12.37488)
		(width 0.3556)
		(layer "F.Cu")
		(net "GND")
	)
	(segment
		(start 190.093346 -221.96679)
		(end 188.988446 -221.96679)
		(width 0.381)
		(layer "F.Cu")
		(net "GND")
	)
	(segment
		(start 204.076046 -206.666592)
		(end 205.180946 -206.666592)
		(width 0.381)
		(layer "F.Cu")
		(net "GND")
	)
	(segment
		(start 117.749066 -217.600276)
		(end 117.749066 -217.064336)
		(width 0.254)
		(layer "F.Cu")
		(net "GND")
	)
	(segment
		(start 132.785866 -232.250488)
		(end 132.785612 -232.250234)
		(width 0.2032)
		(layer "F.Cu")
		(net "GND")
	)
	(segment
		(start 405.648414 -212.616796)
		(end 406.753314 -212.616796)
		(width 0.381)
		(layer "F.Cu")
		(net "GND")
	)
	(segment
		(start 263.624314 -229.616762)
		(end 264.729214 -229.616762)
		(width 0.381)
		(layer "F.Cu")
		(net "GND")
	)
	(segment
		(start 383.07518 -226.017582)
		(end 383.075434 -226.017328)
		(width 0.254)
		(layer "F.Cu")
		(net "GND")
	)
	(segment
		(start 335.255108 -275.080984)
		(end 335.255108 -275.08073)
		(width 0.254)
		(layer "F.Cu")
		(net "GND")
	)
	(segment
		(start 119.158512 -223.297496)
		(end 119.158512 -222.76181)
		(width 0.254)
		(layer "F.Cu")
		(net "GND")
	)
	(segment
		(start 301.343314 -298.466764)
		(end 302.448214 -298.466764)
		(width 0.381)
		(layer "F.Cu")
		(net "GND")
	)
	(segment
		(start 23.228046 -301.866808)
		(end 24.332946 -301.866808)
		(width 0.381)
		(layer "F.Cu")
		(net "GND")
	)
	(segment
		(start 91.544394 -265.592306)
		(end 91.544648 -265.592306)
		(width 0.254)
		(layer "F.Cu")
		(net "GND")
	)
	(segment
		(start 382.715516 -257.45313)
		(end 382.715516 -257.988816)
		(width 0.2032)
		(layer "F.Cu")
		(net "GND")
	)
	(segment
		(start 57.503314 -299.316648)
		(end 58.608214 -299.316648)
		(width 0.381)
		(layer "F.Cu")
		(net "GND")
	)
	(segment
		(start 107.521248 -266.127992)
		(end 107.520994 -266.128246)
		(width 0.254)
		(layer "F.Cu")
		(net "GND")
	)
	(segment
		(start 374.885966 -337.601306)
		(end 374.457976 -337.173316)
		(width 0.2032)
		(layer "F.Cu")
		(net "GND")
	)
	(segment
		(start 383.655062 -278.614378)
		(end 383.655062 -279.150318)
		(width 0.2032)
		(layer "F.Cu")
		(net "GND")
	)
	(segment
		(start 308.887114 -263.616694)
		(end 309.992014 -263.616694)
		(width 0.381)
		(layer "F.Cu")
		(net "GND")
	)
	(segment
		(start 352.641916 -274.26666)
		(end 352.641662 -274.266914)
		(width 0.2032)
		(layer "F.Cu")
		(net "GND")
	)
	(segment
		(start 297.899582 -305.266598)
		(end 299.004482 -305.266598)
		(width 0.381)
		(layer "F.Cu")
		(net "GND")
	)
	(segment
		(start 428.279814 -279.766776)
		(end 429.384714 -279.766776)
		(width 0.381)
		(layer "F.Cu")
		(net "GND")
	)
	(segment
		(start 306.74183 -49.621948)
		(end 306.74183 -50.878486)
		(width 0.3556)
		(layer "F.Cu")
		(net "GND")
	)
	(segment
		(start 33.767014 -266.1666)
		(end 34.871914 -266.1666)
		(width 0.381)
		(layer "F.Cu")
		(net "GND")
	)
	(segment
		(start 48.854614 -198.166736)
		(end 49.959514 -198.166736)
		(width 0.381)
		(layer "F.Cu")
		(net "GND")
	)
	(segment
		(start 16.789146 -290.816792)
		(end 15.684246 -290.816792)
		(width 0.381)
		(layer "F.Cu")
		(net "GND")
	)
	(segment
		(start 93.193362 -338.798916)
		(end 93.193362 -339.1154)
		(width 0.381)
		(layer "F.Cu")
		(net "GND")
	)
	(segment
		(start 458.32014 -382.473454)
		(end 458.32014 -382.15443)
		(width 0.3556)
		(layer "F.Cu")
		(net "GND")
	)
	(segment
		(start 128.196848 -283.497782)
		(end 128.196848 -284.033468)
		(width 0.254)
		(layer "F.Cu")
		(net "GND")
	)
	(segment
		(start 63.942214 -258.516628)
		(end 65.047114 -258.516628)
		(width 0.381)
		(layer "F.Cu")
		(net "GND")
	)
	(segment
		(start 117.35308 -104.465628)
		(end 115.76685 -104.465628)
		(width 0.3556)
		(layer "F.Cu")
		(net "GND")
	)
	(segment
		(start 204.076046 -292.516814)
		(end 205.180946 -292.516814)
		(width 0.381)
		(layer "F.Cu")
		(net "GND")
	)
	(segment
		(start 207.071214 -277.216616)
		(end 208.176114 -277.216616)
		(width 0.381)
		(layer "F.Cu")
		(net "GND")
	)
	(segment
		(start 309.992014 -295.06672)
		(end 308.887114 -295.06672)
		(width 0.381)
		(layer "F.Cu")
		(net "GND")
	)
	(segment
		(start 373.67718 -223.297496)
		(end 373.67718 -222.76181)
		(width 0.254)
		(layer "F.Cu")
		(net "GND")
	)
	(segment
		(start 339.014562 -253.919482)
		(end 339.014816 -253.919736)
		(width 0.2032)
		(layer "F.Cu")
		(net "GND")
	)
	(segment
		(start 23.646892 -416.143948)
		(end 23.037292 -416.143948)
		(width 0.3556)
		(layer "F.Cu")
		(net "GND")
	)
	(segment
		(start 432.379882 -233.86669)
		(end 433.484782 -233.86669)
		(width 0.381)
		(layer "F.Cu")
		(net "GND")
	)
	(segment
		(start 118.09222 -420.320978)
		(end 118.88216 -420.320978)
		(width 0.3556)
		(layer "F.Cu")
		(net "GND")
	)
	(segment
		(start 15.684246 -301.866808)
		(end 16.789146 -301.866808)
		(width 0.381)
		(layer "F.Cu")
		(net "GND")
	)
	(segment
		(start 65.047114 -233.86669)
		(end 66.152014 -233.86669)
		(width 0.381)
		(layer "F.Cu")
		(net "GND")
	)
	(segment
		(start 343.60358 -226.017582)
		(end 343.603834 -226.017328)
		(width 0.254)
		(layer "F.Cu")
		(net "GND")
	)
	(segment
		(start 298.070524 -367.755932)
		(end 297.906948 -367.919508)
		(width 0.381)
		(layer "F.Cu")
		(net "GND")
	)
	(segment
		(start 271.168114 -203.266802)
		(end 270.063214 -203.266802)
		(width 0.381)
		(layer "F.Cu")
		(net "GND")
	)
	(segment
		(start 11.135614 -198.166736)
		(end 12.240514 -198.166736)
		(width 0.381)
		(layer "F.Cu")
		(net "GND")
	)
	(segment
		(start 359.8672 -397.474948)
		(end 360.12882 -397.474948)
		(width 0.3556)
		(layer "F.Cu")
		(net "GND")
	)
	(segment
		(start 385.424934 -245.27256)
		(end 384.485134 -244.73662)
		(width 0.254)
		(layer "F.Cu")
		(net "GND")
	)
	(segment
		(start 137.484866 -240.389156)
		(end 137.014966 -240.667286)
		(width 0.254)
		(layer "F.Cu")
		(net "GND")
	)
	(segment
		(start 459.559914 -227.066602)
		(end 458.455014 -227.066602)
		(width 0.381)
		(layer "F.Cu")
		(net "GND")
	)
	(segment
		(start 94.723712 -246.08663)
		(end 94.723966 -246.086376)
		(width 0.2032)
		(layer "F.Cu")
		(net "GND")
	)
	(segment
		(start 439.923682 -222.816674)
		(end 441.028582 -222.816674)
		(width 0.381)
		(layer "F.Cu")
		(net "GND")
	)
	(segment
		(start 378.37618 -226.017582)
		(end 378.376434 -226.017328)
		(width 0.254)
		(layer "F.Cu")
		(net "GND")
	)
	(segment
		(start 429.384714 -309.51678)
		(end 430.489614 -309.51678)
		(width 0.381)
		(layer "F.Cu")
		(net "GND")
	)
	(segment
		(start 275.268182 -264.466578)
		(end 274.163282 -264.466578)
		(width 0.381)
		(layer "F.Cu")
		(net "GND")
	)
	(segment
		(start 186.649614 -250.866656)
		(end 185.544714 -250.866656)
		(width 0.381)
		(layer "F.Cu")
		(net "GND")
	)
	(segment
		(start 312.987182 -215.166702)
		(end 314.092082 -215.166702)
		(width 0.381)
		(layer "F.Cu")
		(net "GND")
	)
	(segment
		(start 115.869466 -224.111566)
		(end 115.869466 -223.575626)
		(width 0.2032)
		(layer "F.Cu")
		(net "GND")
	)
	(segment
		(start 427.230032 -402.30552)
		(end 426.595032 -402.30552)
		(width 0.3556)
		(layer "F.Cu")
		(net "GND")
	)
	(segment
		(start 99.532694 -271.289272)
		(end 99.532948 -271.289526)
		(width 0.2032)
		(layer "F.Cu")
		(net "GND")
	)
	(segment
		(start 9.92886 -100.866448)
		(end 9.700006 -101.095302)
		(width 0.3556)
		(layer "F.Cu")
		(net "GND")
	)
	(segment
		(start 362.399834 -229.808786)
		(end 362.399834 -229.272846)
		(width 0.2032)
		(layer "F.Cu")
		(net "GND")
	)
	(segment
		(start 254.975614 -290.816792)
		(end 256.080514 -290.816792)
		(width 0.381)
		(layer "F.Cu")
		(net "GND")
	)
	(segment
		(start 23.55215 -176.42967)
		(end 23.760938 -176.220882)
		(width 0.254)
		(layer "F.Cu")
		(net "GND")
	)
	(segment
		(start 94.364048 -281.869896)
		(end 94.364048 -282.405836)
		(width 0.254)
		(layer "F.Cu")
		(net "GND")
	)
	(segment
		(start 211.99221 -22.443948)
		(end 212.798914 -21.637244)
		(width 0.3556)
		(layer "F.Cu")
		(net "GND")
	)
	(segment
		(start 172.77588 -127.364998)
		(end 172.77588 -127.974598)
		(width 0.3556)
		(layer "F.Cu")
		(net "GND")
	)
	(segment
		(start 121.977912 -226.017582)
		(end 121.978166 -226.017328)
		(width 0.254)
		(layer "F.Cu")
		(net "GND")
	)
	(segment
		(start 337.299808 -48.050196)
		(end 336.899758 -48.450246)
		(width 0.2032)
		(layer "F.Cu")
		(net "GND")
	)
	(segment
		(start 277.607014 -250.016772)
		(end 278.711914 -250.016772)
		(width 0.381)
		(layer "F.Cu")
		(net "GND")
	)
	(segment
		(start 173.900846 -246.616728)
		(end 175.005746 -246.616728)
		(width 0.381)
		(layer "F.Cu")
		(net "GND")
	)
	(segment
		(start 196.307964 -78.42377)
		(end 196.307964 -79.135732)
		(width 0.3556)
		(layer "F.Cu")
		(net "GND")
	)
	(segment
		(start 29.666946 -311.216802)
		(end 30.771846 -311.216802)
		(width 0.381)
		(layer "F.Cu")
		(net "GND")
	)
	(segment
		(start 456.116182 -289.966654)
		(end 455.011282 -289.966654)
		(width 0.381)
		(layer "F.Cu")
		(net "GND")
	)
	(segment
		(start 427.766988 -11.26998)
		(end 427.766988 -10.16508)
		(width 0.3556)
		(layer "F.Cu")
		(net "GND")
	)
	(segment
		(start 360.12882 -397.474948)
		(end 360.61904 -396.984728)
		(width 0.3556)
		(layer "F.Cu")
		(net "GND")
	)
	(segment
		(start 202.971146 -227.066602)
		(end 204.076046 -227.066602)
		(width 0.381)
		(layer "F.Cu")
		(net "GND")
	)
	(segment
		(start 195.427346 -263.616694)
		(end 196.532246 -263.616694)
		(width 0.381)
		(layer "F.Cu")
		(net "GND")
	)
	(segment
		(start 385.424934 -225.739198)
		(end 385.424934 -225.203258)
		(width 0.254)
		(layer "F.Cu")
		(net "GND")
	)
	(segment
		(start 447.16319 -11.27125)
		(end 447.16319 -12.37488)
		(width 0.3556)
		(layer "F.Cu")
		(net "GND")
	)
	(segment
		(start 361.929934 -238.761524)
		(end 361.92968 -238.76127)
		(width 0.254)
		(layer "F.Cu")
		(net "GND")
	)
	(segment
		(start 125.267466 -224.111566)
		(end 125.267466 -223.575626)
		(width 0.2032)
		(layer "F.Cu")
		(net "GND")
	)
	(segment
		(start 178.000914 -196.466714)
		(end 176.896014 -196.466714)
		(width 0.381)
		(layer "F.Cu")
		(net "GND")
	)
	(segment
		(start 85.432138 -342.481662)
		(end 85.39607 -342.51773)
		(width 0.3556)
		(layer "F.Cu")
		(net "GND")
	)
	(segment
		(start 48.854614 -264.466578)
		(end 49.959514 -264.466578)
		(width 0.381)
		(layer "F.Cu")
		(net "GND")
	)
	(segment
		(start 101.302312 -234.69219)
		(end 101.302312 -234.15625)
		(width 0.2032)
		(layer "F.Cu")
		(net "GND")
	)
	(segment
		(start 292.278816 -56.559958)
		(end 291.681916 -56.559958)
		(width 0.3556)
		(layer "F.Cu")
		(net "GND")
	)
	(segment
		(start 375.666762 -262.058404)
		(end 375.667016 -262.058658)
		(width 0.254)
		(layer "F.Cu")
		(net "GND")
	)
	(segment
		(start 92.954094 -255.547368)
		(end 92.954348 -255.547622)
		(width 0.2032)
		(layer "F.Cu")
		(net "GND")
	)
	(segment
		(start 135.605266 -224.111566)
		(end 135.605266 -223.575626)
		(width 0.2032)
		(layer "F.Cu")
		(net "GND")
	)
	(segment
		(start 377.076716 -286.7533)
		(end 377.076716 -287.288986)
		(width 0.254)
		(layer "F.Cu")
		(net "GND")
	)
	(segment
		(start 299.6946 -344.700352)
		(end 300.634908 -344.700352)
		(width 0.508)
		(layer "F.Cu")
		(net "GND")
	)
	(segment
		(start 85.905594 -275.35886)
		(end 85.43544 -275.08073)
		(width 0.2032)
		(layer "F.Cu")
		(net "GND")
	)
	(segment
		(start 352.062034 -234.691936)
		(end 352.062034 -234.15625)
		(width 0.2032)
		(layer "F.Cu")
		(net "GND")
	)
	(segment
		(start 28.190698 -138.37666)
		(end 29.223462 -138.37666)
		(width 0.3556)
		(layer "F.Cu")
		(net "GND")
	)
	(segment
		(start 375.55678 -232.528618)
		(end 375.557034 -232.528364)
		(width 0.254)
		(layer "F.Cu")
		(net "GND")
	)
	(segment
		(start 59.842146 -309.51678)
		(end 60.947046 -309.51678)
		(width 0.381)
		(layer "F.Cu")
		(net "GND")
	)
	(segment
		(start 452.016114 -265.316716)
		(end 450.911214 -265.316716)
		(width 0.381)
		(layer "F.Cu")
		(net "GND")
	)
	(segment
		(start 112.512094 -394.881862)
		(end 112.512094 -394.258038)
		(width 0.3556)
		(layer "F.Cu")
		(net "GND")
	)
	(segment
		(start 157.708346 -229.616762)
		(end 158.813246 -229.616762)
		(width 0.381)
		(layer "F.Cu")
		(net "GND")
	)
	(segment
		(start 208.176114 -230.466646)
		(end 209.281014 -230.466646)
		(width 0.381)
		(layer "F.Cu")
		(net "GND")
	)
	(segment
		(start 128.556512 -242.830858)
		(end 128.556512 -242.295172)
		(width 0.2032)
		(layer "F.Cu")
		(net "GND")
	)
	(segment
		(start 8.140446 -217.716608)
		(end 9.245346 -217.716608)
		(width 0.381)
		(layer "F.Cu")
		(net "GND")
	)
	(segment
		(start 113.629948 -261.522972)
		(end 113.629948 -262.058912)
		(width 0.254)
		(layer "F.Cu")
		(net "GND")
	)
	(segment
		(start 188.988446 -311.216802)
		(end 190.093346 -311.216802)
		(width 0.381)
		(layer "F.Cu")
		(net "GND")
	)
	(segment
		(start 134.195566 -233.064304)
		(end 134.195566 -232.528364)
		(width 0.2032)
		(layer "F.Cu")
		(net "GND")
	)
	(segment
		(start 207.70215 -114.0968)
		(end 207.70215 -112.97285)
		(width 0.3556)
		(layer "F.Cu")
		(net "GND")
	)
	(segment
		(start 403.846792 -8.320024)
		(end 403.846792 -7.215124)
		(width 0.3556)
		(layer "F.Cu")
		(net "GND")
	)
	(segment
		(start 91.434666 -227.367084)
		(end 91.434666 -226.831144)
		(width 0.2032)
		(layer "F.Cu")
		(net "GND")
	)
	(segment
		(start 311.509664 -38.89121)
		(end 312.043572 -38.89121)
		(width 0.3556)
		(layer "F.Cu")
		(net "GND")
	)
	(segment
		(start 19.784314 -306.96662)
		(end 20.889214 -306.96662)
		(width 0.381)
		(layer "F.Cu")
		(net "GND")
	)
	(segment
		(start 347.864176 -57.732168)
		(end 347.641418 -57.954926)
		(width 0.2032)
		(layer "F.Cu")
		(net "GND")
	)
	(segment
		(start 285.150814 -258.516628)
		(end 286.255714 -258.516628)
		(width 0.381)
		(layer "F.Cu")
		(net "GND")
	)
	(segment
		(start 46.467776 -392.183366)
		(end 47.21733 -392.183366)
		(width 0.4572)
		(layer "F.Cu")
		(net "GND")
	)
	(segment
		(start 134.195566 -229.808786)
		(end 134.195566 -229.272846)
		(width 0.2032)
		(layer "F.Cu")
		(net "GND")
	)
	(segment
		(start 134.665466 -217.600276)
		(end 134.665466 -217.064336)
		(width 0.2032)
		(layer "F.Cu")
		(net "GND")
	)
	(segment
		(start 132.315712 -222.76181)
		(end 132.315966 -222.761556)
		(width 0.254)
		(layer "F.Cu")
		(net "GND")
	)
	(segment
		(start 371.791738 -413.50438)
		(end 370.615718 -413.50438)
		(width 0.3556)
		(layer "F.Cu")
		(net "GND")
	)
	(segment
		(start 347.942916 -257.45313)
		(end 347.942916 -257.988816)
		(width 0.2032)
		(layer "F.Cu")
		(net "GND")
	)
	(segment
		(start 371.79758 -222.76181)
		(end 371.797834 -222.761556)
		(width 0.254)
		(layer "F.Cu")
		(net "GND")
	)
	(segment
		(start 131.485894 -277.800562)
		(end 131.486148 -278.336502)
		(width 0.2032)
		(layer "F.Cu")
		(net "GND")
	)
	(segment
		(start 428.279814 -301.866808)
		(end 429.384714 -301.866808)
		(width 0.381)
		(layer "F.Cu")
		(net "GND")
	)
	(segment
		(start 400.24685 -11.26998)
		(end 400.24685 -10.16508)
		(width 0.3556)
		(layer "F.Cu")
		(net "GND")
	)
	(segment
		(start 463.659982 -314.616592)
		(end 462.555082 -314.616592)
		(width 0.381)
		(layer "F.Cu")
		(net "GND")
	)
	(segment
		(start 266.619482 -286.56661)
		(end 267.724382 -286.56661)
		(width 0.381)
		(layer "F.Cu")
		(net "GND")
	)
	(segment
		(start 18.679414 -241.516662)
		(end 19.784314 -241.516662)
		(width 0.381)
		(layer "F.Cu")
		(net "GND")
	)
	(segment
		(start 386.474716 -275.35886)
		(end 386.944616 -275.080984)
		(width 0.254)
		(layer "F.Cu")
		(net "GND")
	)
	(segment
		(start 60.947046 -199.01662)
		(end 62.051946 -199.01662)
		(width 0.381)
		(layer "F.Cu")
		(net "GND")
	)
	(segment
		(start 377.43638 -249.342148)
		(end 377.43638 -248.806208)
		(width 0.2032)
		(layer "F.Cu")
		(net "GND")
	)
	(segment
		(start 85.274404 -278.614378)
		(end 85.905594 -278.614378)
		(width 0.2032)
		(layer "F.Cu")
		(net "GND")
	)
	(segment
		(start 215.719914 -262.76681)
		(end 216.824814 -262.76681)
		(width 0.381)
		(layer "F.Cu")
		(net "GND")
	)
	(segment
		(start 122.448066 -238.761524)
		(end 122.447812 -238.76127)
		(width 0.2032)
		(layer "F.Cu")
		(net "GND")
	)
	(segment
		(start 194.193414 -245.76659)
		(end 193.088514 -245.76659)
		(width 0.381)
		(layer "F.Cu")
		(net "GND")
	)
	(segment
		(start 339.014562 -253.383796)
		(end 339.014562 -253.919482)
		(width 0.2032)
		(layer "F.Cu")
		(net "GND")
	)
	(segment
		(start 307.782214 -201.56678)
		(end 308.887114 -201.56678)
		(width 0.381)
		(layer "F.Cu")
		(net "GND")
	)
	(segment
		(start 173.900846 -285.716726)
		(end 175.005746 -285.716726)
		(width 0.381)
		(layer "F.Cu")
		(net "GND")
	)
	(segment
		(start 425.940982 -244.066568)
		(end 427.045882 -244.066568)
		(width 0.381)
		(layer "F.Cu")
		(net "GND")
	)
	(segment
		(start 33.048956 -391.635996)
		(end 32.350964 -391.635996)
		(width 0.4572)
		(layer "F.Cu")
		(net "GND")
	)
	(segment
		(start 328.244962 -47.95012)
		(end 328.625708 -47.510446)
		(width 0.1778)
		(layer "F.Cu")
		(net "GND")
	)
	(segment
		(start 104.591866 -214.344758)
		(end 104.591866 -213.732618)
		(width 0.254)
		(layer "F.Cu")
		(net "GND")
	)
	(segment
		(start 337.495134 -232.250488)
		(end 337.49488 -232.250234)
		(width 0.2032)
		(layer "F.Cu")
		(net "GND")
	)
	(segment
		(start 347.597222 -47.5361)
		(end 347.510862 -47.44974)
		(width 0.1524)
		(layer "F.Cu")
		(net "GND")
	)
	(segment
		(start 111.640112 -216.250774)
		(end 111.640366 -216.25052)
		(width 0.254)
		(layer "F.Cu")
		(net "GND")
	)
	(segment
		(start 265.029696 -72.662542)
		(end 264.394696 -72.662542)
		(width 0.381)
		(layer "F.Cu")
		(net "GND")
	)
	(segment
		(start 164.018214 -210.066636)
		(end 162.913314 -210.066636)
		(width 0.381)
		(layer "F.Cu")
		(net "GND")
	)
	(segment
		(start 173.900846 -238.966756)
		(end 172.795946 -238.966756)
		(width 0.381)
		(layer "F.Cu")
		(net "GND")
	)
	(segment
		(start 97.543112 -239.57534)
		(end 97.543366 -239.575086)
		(width 0.2032)
		(layer "F.Cu")
		(net "GND")
	)
	(segment
		(start 7.035546 -258.516628)
		(end 8.140446 -258.516628)
		(width 0.381)
		(layer "F.Cu")
		(net "GND")
	)
	(segment
		(start 118.328694 -264.778236)
		(end 118.328694 -265.314176)
		(width 0.254)
		(layer "F.Cu")
		(net "GND")
	)
	(segment
		(start 349.352362 -279.96388)
		(end 349.352616 -279.964134)
		(width 0.2032)
		(layer "F.Cu")
		(net "GND")
	)
	(segment
		(start 12.240514 -264.466578)
		(end 13.345414 -264.466578)
		(width 0.381)
		(layer "F.Cu")
		(net "GND")
	)
	(segment
		(start 351.592134 -227.367084)
		(end 351.592134 -226.831144)
		(width 0.254)
		(layer "F.Cu")
		(net "GND")
	)
	(segment
		(start 345.002358 -354.58908)
		(end 344.260678 -354.58908)
		(width 0.3556)
		(layer "F.Cu")
		(net "GND")
	)
	(segment
		(start 406.753314 -301.866808)
		(end 408.11831 -301.866808)
		(width 0.381)
		(layer "F.Cu")
		(net "GND")
	)
	(segment
		(start 444.472314 -240.666778)
		(end 445.577214 -240.666778)
		(width 0.381)
		(layer "F.Cu")
		(net "GND")
	)
	(segment
		(start 129.026666 -228.99497)
		(end 129.026412 -228.994716)
		(width 0.2032)
		(layer "F.Cu")
		(net "GND")
	)
	(segment
		(start 180.339746 -242.3668)
		(end 181.444646 -242.3668)
		(width 0.381)
		(layer "F.Cu")
		(net "GND")
	)
	(segment
		(start 175.552862 -33.420812)
		(end 175.552862 -32.351472)
		(width 0.254)
		(layer "F.Cu")
		(net "GND")
	)
	(segment
		(start 26.223214 -194.766692)
		(end 27.328114 -194.766692)
		(width 0.381)
		(layer "F.Cu")
		(net "GND")
	)
	(segment
		(start 121.977912 -237.411768)
		(end 121.978166 -237.411514)
		(width 0.254)
		(layer "F.Cu")
		(net "GND")
	)
	(segment
		(start 285.150814 -287.416748)
		(end 286.255714 -287.416748)
		(width 0.381)
		(layer "F.Cu")
		(net "GND")
	)
	(segment
		(start 207.071214 -312.91657)
		(end 208.176114 -312.91657)
		(width 0.381)
		(layer "F.Cu")
		(net "GND")
	)
	(segment
		(start 271.168114 -242.3668)
		(end 270.063214 -242.3668)
		(width 0.381)
		(layer "F.Cu")
		(net "GND")
	)
	(segment
		(start 161.642552 -312.91657)
		(end 161.61893 -312.892948)
		(width 0.381)
		(layer "F.Cu")
		(net "GND")
	)
	(segment
		(start 44.754546 -246.616728)
		(end 45.859446 -246.616728)
		(width 0.381)
		(layer "F.Cu")
		(net "GND")
	)
	(segment
		(start 120.208294 -282.683966)
		(end 120.208548 -282.68422)
		(width 0.254)
		(layer "F.Cu")
		(net "GND")
	)
	(segment
		(start 35.976814 -278.916638)
		(end 34.871914 -278.916638)
		(width 0.381)
		(layer "F.Cu")
		(net "GND")
	)
	(segment
		(start 59.842146 -258.516628)
		(end 60.947046 -258.516628)
		(width 0.381)
		(layer "F.Cu")
		(net "GND")
	)
	(segment
		(start 347.36278 -249.342148)
		(end 347.363034 -249.341894)
		(width 0.2032)
		(layer "F.Cu")
		(net "GND")
	)
	(segment
		(start 11.135614 -278.916638)
		(end 12.240514 -278.916638)
		(width 0.381)
		(layer "F.Cu")
		(net "GND")
	)
	(segment
		(start 364.028482 -393.988036)
		(end 364.537752 -393.988036)
		(width 0.3556)
		(layer "F.Cu")
		(net "GND")
	)
	(segment
		(start 204.076046 -279.766776)
		(end 205.180946 -279.766776)
		(width 0.381)
		(layer "F.Cu")
		(net "GND")
	)
	(segment
		(start 340.784434 -241.202972)
		(end 340.784434 -240.667286)
		(width 0.2032)
		(layer "F.Cu")
		(net "GND")
	)
	(segment
		(start 181.444646 -246.616728)
		(end 182.549546 -246.616728)
		(width 0.381)
		(layer "F.Cu")
		(net "GND")
	)
	(segment
		(start 53.403246 -248.31675)
		(end 54.508146 -248.31675)
		(width 0.381)
		(layer "F.Cu")
		(net "GND")
	)
	(segment
		(start 344.073734 -228.99497)
		(end 344.07348 -228.994716)
		(width 0.2032)
		(layer "F.Cu")
		(net "GND")
	)
	(segment
		(start 169.352214 -247.466612)
		(end 170.457114 -247.466612)
		(width 0.381)
		(layer "F.Cu")
		(net "GND")
	)
	(segment
		(start 373.677434 -234.691936)
		(end 373.677434 -234.15625)
		(width 0.2032)
		(layer "F.Cu")
		(net "GND")
	)
	(segment
		(start 266.619482 -264.466578)
		(end 267.724382 -264.466578)
		(width 0.381)
		(layer "F.Cu")
		(net "GND")
	)
	(segment
		(start 63.942214 -266.1666)
		(end 65.047114 -266.1666)
		(width 0.381)
		(layer "F.Cu")
		(net "GND")
	)
	(segment
		(start 60.947046 -206.666592)
		(end 62.267846 -206.666592)
		(width 0.381)
		(layer "F.Cu")
		(net "GND")
	)
	(segment
		(start 365.799116 -266.127992)
		(end 365.798862 -266.128246)
		(width 0.2032)
		(layer "F.Cu")
		(net "GND")
	)
	(segment
		(start 26.223214 -280.61666)
		(end 27.328114 -280.61666)
		(width 0.381)
		(layer "F.Cu")
		(net "GND")
	)
	(segment
		(start 29.666946 -265.316716)
		(end 30.771846 -265.316716)
		(width 0.381)
		(layer "F.Cu")
		(net "GND")
	)
	(segment
		(start 278.711914 -281.466798)
		(end 279.816814 -281.466798)
		(width 0.381)
		(layer "F.Cu")
		(net "GND")
	)
	(segment
		(start 290.355782 -294.216582)
		(end 291.460682 -294.216582)
		(width 0.381)
		(layer "F.Cu")
		(net "GND")
	)
	(segment
		(start 149.768306 -64.059308)
		(end 150.377906 -64.059308)
		(width 0.3556)
		(layer "F.Cu")
		(net "GND")
	)
	(segment
		(start 345.318588 -38.880288)
		(end 345.403932 -38.880288)
		(width 0.2032)
		(layer "F.Cu")
		(net "GND")
	)
	(segment
		(start 180.555646 -112.175544)
		(end 180.955696 -111.775494)
		(width 0.3556)
		(layer "F.Cu")
		(net "GND")
	)
	(segment
		(start 135.135112 -228.1809)
		(end 135.135366 -228.180646)
		(width 0.2032)
		(layer "F.Cu")
		(net "GND")
	)
	(segment
		(start 432.379882 -267.866622)
		(end 433.484782 -267.866622)
		(width 0.381)
		(layer "F.Cu")
		(net "GND")
	)
	(segment
		(start 251.16409 -47.721012)
		(end 251.16409 -47.102522)
		(width 0.3556)
		(layer "F.Cu")
		(net "GND")
	)
	(segment
		(start 48.854614 -261.066788)
		(end 49.959514 -261.066788)
		(width 0.381)
		(layer "F.Cu")
		(net "GND")
	)
	(segment
		(start 22.123146 -214.316564)
		(end 23.228046 -214.316564)
		(width 0.381)
		(layer "F.Cu")
		(net "GND")
	)
	(segment
		(start 383.07518 -242.830858)
		(end 383.07518 -242.295172)
		(width 0.2032)
		(layer "F.Cu")
		(net "GND")
	)
	(segment
		(start 14.579346 -223.666558)
		(end 15.684246 -223.666558)
		(width 0.381)
		(layer "F.Cu")
		(net "GND")
	)
	(segment
		(start 92.844112 -244.458744)
		(end 92.844366 -244.45849)
		(width 0.2032)
		(layer "F.Cu")
		(net "GND")
	)
	(segment
		(start 282.811982 -267.866622)
		(end 283.916882 -267.866622)
		(width 0.381)
		(layer "F.Cu")
		(net "GND")
	)
	(segment
		(start 173.900846 -298.466764)
		(end 175.005746 -298.466764)
		(width 0.381)
		(layer "F.Cu")
		(net "GND")
	)
	(segment
		(start 340.894162 -285.939484)
		(end 340.894162 -286.47517)
		(width 0.2032)
		(layer "F.Cu")
		(net "GND")
	)
	(segment
		(start 405.648414 -307.816758)
		(end 406.753314 -307.816758)
		(width 0.381)
		(layer "F.Cu")
		(net "GND")
	)
	(segment
		(start 53.403246 -221.96679)
		(end 54.508146 -221.96679)
		(width 0.381)
		(layer "F.Cu")
		(net "GND")
	)
	(segment
		(start 463.659982 -221.116652)
		(end 464.764882 -221.116652)
		(width 0.381)
		(layer "F.Cu")
		(net "GND")
	)
	(segment
		(start 88.596216 -342.106758)
		(end 88.43264 -342.270334)
		(width 0.3556)
		(layer "F.Cu")
		(net "GND")
	)
	(segment
		(start 171.41952 -424.398948)
		(end 170.59148 -424.398948)
		(width 0.3556)
		(layer "F.Cu")
		(net "GND")
	)
	(segment
		(start 99.532694 -257.175254)
		(end 99.532694 -256.639314)
		(width 0.2032)
		(layer "F.Cu")
		(net "GND")
	)
	(segment
		(start 345.593162 -276.172676)
		(end 345.593162 -276.708616)
		(width 0.2032)
		(layer "F.Cu")
		(net "GND")
	)
	(segment
		(start 125.377448 -278.614378)
		(end 125.377448 -279.150064)
		(width 0.254)
		(layer "F.Cu")
		(net "GND")
	)
	(segment
		(start 261.285482 -202.416664)
		(end 260.180582 -202.416664)
		(width 0.381)
		(layer "F.Cu")
		(net "GND")
	)
	(segment
		(start 88.725248 -285.125414)
		(end 88.724994 -285.661354)
		(width 0.2032)
		(layer "F.Cu")
		(net "GND")
	)
	(segment
		(start 202.971146 -317.166752)
		(end 204.076046 -317.166752)
		(width 0.381)
		(layer "F.Cu")
		(net "GND")
	)
	(segment
		(start 56.398414 -266.1666)
		(end 57.503314 -266.1666)
		(width 0.381)
		(layer "F.Cu")
		(net "GND")
	)
	(segment
		(start 312.987182 -312.91657)
		(end 314.307982 -312.91657)
		(width 0.381)
		(layer "F.Cu")
		(net "GND")
	)
	(segment
		(start 337.134962 -277.800562)
		(end 336.664808 -277.522686)
		(width 0.254)
		(layer "F.Cu")
		(net "GND")
	)
	(segment
		(start 98.013266 -242.017042)
		(end 98.013012 -242.016788)
		(width 0.2032)
		(layer "F.Cu")
		(net "GND")
	)
	(segment
		(start 350.652334 -214.344758)
		(end 350.652334 -213.732618)
		(width 0.254)
		(layer "F.Cu")
		(net "GND")
	)
	(segment
		(start 429.384714 -229.616762)
		(end 430.489614 -229.616762)
		(width 0.381)
		(layer "F.Cu")
		(net "GND")
	)
	(segment
		(start 405.410924 -238.966756)
		(end 406.753314 -238.966756)
		(width 0.381)
		(layer "F.Cu")
		(net "GND")
	)
	(segment
		(start 104.121712 -231.436418)
		(end 104.121966 -231.436164)
		(width 0.2032)
		(layer "F.Cu")
		(net "GND")
	)
	(segment
		(start 356.76078 -222.76181)
		(end 356.761034 -222.761556)
		(width 0.254)
		(layer "F.Cu")
		(net "GND")
	)
	(segment
		(start 63.942214 -269.566644)
		(end 65.047114 -269.566644)
		(width 0.381)
		(layer "F.Cu")
		(net "GND")
	)
	(segment
		(start 352.171762 -285.939484)
		(end 352.171762 -286.475424)
		(width 0.254)
		(layer "F.Cu")
		(net "GND")
	)
	(segment
		(start 193.088514 -235.566712)
		(end 191.983614 -235.566712)
		(width 0.381)
		(layer "F.Cu")
		(net "GND")
	)
	(segment
		(start 336.085434 -224.925382)
		(end 336.085434 -224.389442)
		(width 0.254)
		(layer "F.Cu")
		(net "GND")
	)
	(segment
		(start 350.762062 -270.47571)
		(end 350.762062 -271.011396)
		(width 0.2032)
		(layer "F.Cu")
		(net "GND")
	)
	(segment
		(start 65.047114 -249.166634)
		(end 66.152014 -249.166634)
		(width 0.381)
		(layer "F.Cu")
		(net "GND")
	)
	(segment
		(start 338.120736 -40.931846)
		(end 339.209888 -40.931846)
		(width 0.2032)
		(layer "F.Cu")
		(net "GND")
	)
	(segment
		(start 104.121966 -234.691936)
		(end 104.121966 -234.15625)
		(width 0.254)
		(layer "F.Cu")
		(net "GND")
	)
	(segment
		(start 100.832412 -243.644674)
		(end 100.832412 -243.108988)
		(width 0.254)
		(layer "F.Cu")
		(net "GND")
	)
	(segment
		(start 435.823614 -267.016738)
		(end 436.928514 -267.016738)
		(width 0.381)
		(layer "F.Cu")
		(net "GND")
	)
	(segment
		(start 23.31847 -428.401988)
		(end 23.93188 -428.401988)
		(width 0.3556)
		(layer "F.Cu")
		(net "GND")
	)
	(segment
		(start 94.856046 -415.168588)
		(end 95.13824 -414.886394)
		(width 0.3556)
		(layer "F.Cu")
		(net "GND")
	)
	(segment
		(start 166.357046 -295.06672)
		(end 165.252146 -295.06672)
		(width 0.381)
		(layer "F.Cu")
		(net "GND")
	)
	(segment
		(start 378.84608 -242.016788)
		(end 378.84608 -241.481102)
		(width 0.2032)
		(layer "F.Cu")
		(net "GND")
	)
	(segment
		(start 123.857512 -222.76181)
		(end 123.857766 -222.761556)
		(width 0.254)
		(layer "F.Cu")
		(net "GND")
	)
	(segment
		(start 311.882282 -241.516662)
		(end 312.987182 -241.516662)
		(width 0.381)
		(layer "F.Cu")
		(net "GND")
	)
	(segment
		(start 136.075166 -226.017328)
		(end 136.075166 -226.553268)
		(width 0.254)
		(layer "F.Cu")
		(net "GND")
	)
	(segment
		(start 444.472314 -201.56678)
		(end 443.367414 -201.56678)
		(width 0.381)
		(layer "F.Cu")
		(net "GND")
	)
	(segment
		(start 263.624314 -240.666778)
		(end 264.729214 -240.666778)
		(width 0.381)
		(layer "F.Cu")
		(net "GND")
	)
	(segment
		(start 101.772466 -238.761524)
		(end 101.772212 -238.76127)
		(width 0.2032)
		(layer "F.Cu")
		(net "GND")
	)
	(segment
		(start 371.907562 -255.011682)
		(end 371.907562 -255.547368)
		(width 0.2032)
		(layer "F.Cu")
		(net "GND")
	)
	(segment
		(start 38.315646 -265.316716)
		(end 37.210746 -265.316716)
		(width 0.381)
		(layer "F.Cu")
		(net "GND")
	)
	(segment
		(start 448.572382 -282.316682)
		(end 447.467482 -282.316682)
		(width 0.381)
		(layer "F.Cu")
		(net "GND")
	)
	(segment
		(start 111.764826 -401.195286)
		(end 111.764826 -400.509486)
		(width 0.3556)
		(layer "F.Cu")
		(net "GND")
	)
	(segment
		(start 26.223214 -316.316614)
		(end 27.328114 -316.316614)
		(width 0.381)
		(layer "F.Cu")
		(net "GND")
	)
	(segment
		(start 256.080514 -272.116804)
		(end 257.185414 -272.116804)
		(width 0.381)
		(layer "F.Cu")
		(net "GND")
	)
	(segment
		(start 266.619482 -282.316682)
		(end 267.724382 -282.316682)
		(width 0.381)
		(layer "F.Cu")
		(net "GND")
	)
	(segment
		(start 15.684246 -290.816792)
		(end 14.579346 -290.816792)
		(width 0.381)
		(layer "F.Cu")
		(net "GND")
	)
	(segment
		(start 308.013354 -435.27472)
		(end 308.402482 -435.663848)
		(width 0.3556)
		(layer "F.Cu")
		(net "GND")
	)
	(segment
		(start 272.273014 -212.616796)
		(end 271.168114 -212.616796)
		(width 0.381)
		(layer "F.Cu")
		(net "GND")
	)
	(segment
		(start 60.947046 -238.966756)
		(end 62.267846 -238.966756)
		(width 0.381)
		(layer "F.Cu")
		(net "GND")
	)
	(segment
		(start 409.748482 -202.416664)
		(end 410.853382 -202.416664)
		(width 0.381)
		(layer "F.Cu")
		(net "GND")
	)
	(segment
		(start 272.273014 -234.716574)
		(end 271.168114 -234.716574)
		(width 0.381)
		(layer "F.Cu")
		(net "GND")
	)
	(segment
		(start 85.795866 -217.600276)
		(end 85.795866 -217.06459)
		(width 0.2032)
		(layer "F.Cu")
		(net "GND")
	)
	(segment
		(start 131.485894 -282.683966)
		(end 131.486148 -282.68422)
		(width 0.254)
		(layer "F.Cu")
		(net "GND")
	)
	(segment
		(start 125.737112 -239.57534)
		(end 125.737366 -239.575086)
		(width 0.2032)
		(layer "F.Cu")
		(net "GND")
	)
	(segment
		(start 345.593162 -261.522718)
		(end 345.593162 -262.058658)
		(width 0.2032)
		(layer "F.Cu")
		(net "GND")
	)
	(segment
		(start 43.520614 -294.216582)
		(end 42.415714 -294.216582)
		(width 0.381)
		(layer "F.Cu")
		(net "GND")
	)
	(segment
		(start 328.244962 -54.953408)
		(end 328.194162 -55.004208)
		(width 0.2032)
		(layer "F.Cu")
		(net "GND")
	)
	(segment
		(start 383.545334 -246.900446)
		(end 384.015234 -247.178322)
		(width 0.254)
		(layer "F.Cu")
		(net "GND")
	)
	(segment
		(start 282.811982 -207.51673)
		(end 283.916882 -207.51673)
		(width 0.381)
		(layer "F.Cu")
		(net "GND")
	)
	(segment
		(start 162.913314 -219.41663)
		(end 164.063172 -219.41663)
		(width 0.381)
		(layer "F.Cu")
		(net "GND")
	)
	(segment
		(start 18.679414 -295.916604)
		(end 19.784314 -295.916604)
		(width 0.381)
		(layer "F.Cu")
		(net "GND")
	)
	(segment
		(start 420.736014 -260.21665)
		(end 421.840914 -260.21665)
		(width 0.381)
		(layer "F.Cu")
		(net "GND")
	)
	(segment
		(start 305.443382 -245.76659)
		(end 306.548282 -245.76659)
		(width 0.381)
		(layer "F.Cu")
		(net "GND")
	)
	(segment
		(start 14.426946 -389.151876)
		(end 15.036546 -389.151876)
		(width 0.3556)
		(layer "F.Cu")
		(net "GND")
	)
	(segment
		(start 413.192214 -315.46673)
		(end 414.297114 -315.46673)
		(width 0.381)
		(layer "F.Cu")
		(net "GND")
	)
	(segment
		(start 14.579346 -315.46673)
		(end 15.684246 -315.46673)
		(width 0.381)
		(layer "F.Cu")
		(net "GND")
	)
	(segment
		(start 331.608176 -43.751246)
		(end 331.069188 -43.751246)
		(width 0.2032)
		(layer "F.Cu")
		(net "GND")
	)
	(segment
		(start 93.893894 -264.778236)
		(end 93.893894 -265.313922)
		(width 0.2032)
		(layer "F.Cu")
		(net "GND")
	)
	(segment
		(start 284.599888 -410.89199)
		(end 284.599888 -410.21254)
		(width 0.3556)
		(layer "F.Cu")
		(net "GND")
	)
	(segment
		(start 328.168 -52.028852)
		(end 328.244962 -51.95189)
		(width 0.2032)
		(layer "F.Cu")
		(net "GND")
	)
	(segment
		(start 301.190406 -424.507152)
		(end 301.190406 -424.95597)
		(width 0.3556)
		(layer "F.Cu")
		(net "GND")
	)
	(segment
		(start 457.221082 -305.266598)
		(end 456.116182 -305.266598)
		(width 0.381)
		(layer "F.Cu")
		(net "GND")
	)
	(segment
		(start 272.273014 -263.616694)
		(end 271.168114 -263.616694)
		(width 0.381)
		(layer "F.Cu")
		(net "GND")
	)
	(segment
		(start 121.977912 -234.69219)
		(end 121.978166 -234.691936)
		(width 0.254)
		(layer "F.Cu")
		(net "GND")
	)
	(segment
		(start 429.384714 -258.516628)
		(end 430.489614 -258.516628)
		(width 0.381)
		(layer "F.Cu")
		(net "GND")
	)
	(segment
		(start 410.853382 -233.86669)
		(end 409.748482 -233.86669)
		(width 0.381)
		(layer "F.Cu")
		(net "GND")
	)
	(segment
		(start 367.208562 -285.939484)
		(end 367.208562 -286.47517)
		(width 0.254)
		(layer "F.Cu")
		(net "GND")
	)
	(segment
		(start 459.559914 -279.766776)
		(end 460.664814 -279.766776)
		(width 0.381)
		(layer "F.Cu")
		(net "GND")
	)
	(segment
		(start 436.928514 -217.716608)
		(end 438.033414 -217.716608)
		(width 0.381)
		(layer "F.Cu")
		(net "GND")
	)
	(segment
		(start 293.799514 -197.316598)
		(end 292.694614 -197.316598)
		(width 0.381)
		(layer "F.Cu")
		(net "GND")
	)
	(segment
		(start 189.262004 -13.599922)
		(end 189.26175 -13.599668)
		(width 0.3556)
		(layer "F.Cu")
		(net "GND")
	)
	(segment
		(start 357.70058 -226.553268)
		(end 357.70058 -226.017582)
		(width 0.254)
		(layer "F.Cu")
		(net "GND")
	)
	(segment
		(start 372.267734 -240.389156)
		(end 372.26748 -240.388902)
		(width 0.2032)
		(layer "F.Cu")
		(net "GND")
	)
	(segment
		(start 285.150814 -315.46673)
		(end 286.255714 -315.46673)
		(width 0.381)
		(layer "F.Cu")
		(net "GND")
	)
	(segment
		(start 324.6882 -20.632928)
		(end 324.67423 -20.646898)
		(width 0.3556)
		(layer "F.Cu")
		(net "GND")
	)
	(segment
		(start 22.123146 -270.416782)
		(end 23.228046 -270.416782)
		(width 0.381)
		(layer "F.Cu")
		(net "GND")
	)
	(segment
		(start 435.823614 -223.666558)
		(end 436.928514 -223.666558)
		(width 0.381)
		(layer "F.Cu")
		(net "GND")
	)
	(segment
		(start 63.42253 -36.65728)
		(end 64.05753 -36.65728)
		(width 0.3556)
		(layer "F.Cu")
		(net "GND")
	)
	(segment
		(start 342.194134 -246.900446)
		(end 342.194134 -246.364506)
		(width 0.2032)
		(layer "F.Cu")
		(net "GND")
	)
	(segment
		(start 31.69793 -429.859948)
		(end 32.30753 -429.859948)
		(width 0.3556)
		(layer "F.Cu")
		(net "GND")
	)
	(segment
		(start 304.338482 -228.766624)
		(end 305.443382 -228.766624)
		(width 0.381)
		(layer "F.Cu")
		(net "GND")
	)
	(segment
		(start 364.859062 -264.500106)
		(end 364.859062 -264.50036)
		(width 0.2032)
		(layer "F.Cu")
		(net "GND")
	)
	(segment
		(start 22.123146 -233.016806)
		(end 23.228046 -233.016806)
		(width 0.381)
		(layer "F.Cu")
		(net "GND")
	)
	(segment
		(start 30.771846 -270.416782)
		(end 31.876746 -270.416782)
		(width 0.381)
		(layer "F.Cu")
		(net "GND")
	)
	(segment
		(start 12.240514 -228.766624)
		(end 13.345414 -228.766624)
		(width 0.381)
		(layer "F.Cu")
		(net "GND")
	)
	(segment
		(start 423.823892 -402.671534)
		(end 423.214292 -402.671534)
		(width 0.381)
		(layer "F.Cu")
		(net "GND")
	)
	(segment
		(start 184.439814 -297.616626)
		(end 185.544714 -297.616626)
		(width 0.381)
		(layer "F.Cu")
		(net "GND")
	)
	(segment
		(start 29.666946 -309.51678)
		(end 30.771846 -309.51678)
		(width 0.381)
		(layer "F.Cu")
		(net "GND")
	)
	(segment
		(start 340.894162 -272.917158)
		(end 340.894162 -273.452844)
		(width 0.2032)
		(layer "F.Cu")
		(net "GND")
	)
	(segment
		(start 95.663766 -220.041724)
		(end 95.663766 -219.506038)
		(width 0.254)
		(layer "F.Cu")
		(net "GND")
	)
	(segment
		(start 406.753314 -307.816758)
		(end 407.858214 -307.816758)
		(width 0.381)
		(layer "F.Cu")
		(net "GND")
	)
	(segment
		(start 416.484562 -181.857904)
		(end 416.484562 -182.151528)
		(width 0.2032)
		(layer "F.Cu")
		(net "GND")
	)
	(segment
		(start 84.966048 -260.708902)
		(end 84.495894 -260.430772)
		(width 0.254)
		(layer "F.Cu")
		(net "GND")
	)
	(segment
		(start 22.123146 -220.266768)
		(end 23.228046 -220.266768)
		(width 0.381)
		(layer "F.Cu")
		(net "GND")
	)
	(segment
		(start 104.121966 -220.041724)
		(end 104.121966 -219.506038)
		(width 0.254)
		(layer "F.Cu")
		(net "GND")
	)
	(segment
		(start 178.960272 -358.535986)
		(end 178.960272 -359.186226)
		(width 0.3556)
		(layer "F.Cu")
		(net "GND")
	)
	(segment
		(start 452.016114 -204.96657)
		(end 450.911214 -204.96657)
		(width 0.381)
		(layer "F.Cu")
		(net "GND")
	)
	(segment
		(start 409.748482 -286.69361)
		(end 409.875482 -286.56661)
		(width 0.381)
		(layer "F.Cu")
		(net "GND")
	)
	(segment
		(start 11.135614 -261.066788)
		(end 12.240514 -261.066788)
		(width 0.381)
		(layer "F.Cu")
		(net "GND")
	)
	(segment
		(start 340.78418 -222.76181)
		(end 340.784434 -222.761556)
		(width 0.254)
		(layer "F.Cu")
		(net "GND")
	)
	(segment
		(start 441.028582 -275.516594)
		(end 442.133482 -275.516594)
		(width 0.381)
		(layer "F.Cu")
		(net "GND")
	)
	(segment
		(start 449.677282 -294.216582)
		(end 448.572382 -294.216582)
		(width 0.381)
		(layer "F.Cu")
		(net "GND")
	)
	(segment
		(start 281.707082 -303.566576)
		(end 282.811982 -303.566576)
		(width 0.381)
		(layer "F.Cu")
		(net "GND")
	)
	(segment
		(start 406.753314 -258.516628)
		(end 407.858214 -258.516628)
		(width 0.381)
		(layer "F.Cu")
		(net "GND")
	)
	(segment
		(start 180.339746 -195.616576)
		(end 181.444646 -195.616576)
		(width 0.381)
		(layer "F.Cu")
		(net "GND")
	)
	(segment
		(start 410.853382 -269.566644)
		(end 411.958282 -269.566644)
		(width 0.381)
		(layer "F.Cu")
		(net "GND")
	)
	(segment
		(start 261.285482 -303.566576)
		(end 260.180582 -303.566576)
		(width 0.381)
		(layer "F.Cu")
		(net "GND")
	)
	(segment
		(start 300.022514 -234.716574)
		(end 301.343314 -234.716574)
		(width 0.381)
		(layer "F.Cu")
		(net "GND")
	)
	(segment
		(start 356.870762 -277.800562)
		(end 356.870762 -278.336502)
		(width 0.254)
		(layer "F.Cu")
		(net "GND")
	)
	(segment
		(start 432.757072 -177.503074)
		(end 432.757072 -176.671478)
		(width 0.254)
		(layer "F.Cu")
		(net "GND")
	)
	(segment
		(start 338.544916 -262.336534)
		(end 338.544916 -262.872474)
		(width 0.2032)
		(layer "F.Cu")
		(net "GND")
	)
	(segment
		(start 285.150814 -261.916672)
		(end 286.255714 -261.916672)
		(width 0.381)
		(layer "F.Cu")
		(net "GND")
	)
	(segment
		(start 343.133934 -224.111566)
		(end 343.133934 -223.575626)
		(width 0.2032)
		(layer "F.Cu")
		(net "GND")
	)
	(segment
		(start 120.76049 -425.059348)
		(end 121.37009 -425.059348)
		(width 0.3556)
		(layer "F.Cu")
		(net "GND")
	)
	(segment
		(start 272.273014 -195.616576)
		(end 271.168114 -195.616576)
		(width 0.381)
		(layer "F.Cu")
		(net "GND")
	)
	(segment
		(start 105.061512 -229.808786)
		(end 105.061766 -229.808532)
		(width 0.2032)
		(layer "F.Cu")
		(net "GND")
	)
	(segment
		(start 421.840914 -217.716608)
		(end 423.173652 -217.716608)
		(width 0.381)
		(layer "F.Cu")
		(net "GND")
	)
	(segment
		(start 207.071214 -299.316648)
		(end 208.176114 -299.316648)
		(width 0.381)
		(layer "F.Cu")
		(net "GND")
	)
	(segment
		(start 332.796134 -238.761524)
		(end 332.326234 -239.0394)
		(width 0.254)
		(layer "F.Cu")
		(net "GND")
	)
	(segment
		(start 372.377716 -265.592306)
		(end 372.377716 -266.127992)
		(width 0.254)
		(layer "F.Cu")
		(net "GND")
	)
	(segment
		(start 333.371952 -343.06002)
		(end 333.335884 -343.096088)
		(width 0.381)
		(layer "F.Cu")
		(net "GND")
	)
	(segment
		(start 348.30258 -242.295172)
		(end 348.302834 -242.294918)
		(width 0.254)
		(layer "F.Cu")
		(net "GND")
	)
	(segment
		(start 334.315562 -253.383796)
		(end 333.845408 -253.10592)
		(width 0.2032)
		(layer "F.Cu")
		(net "GND")
	)
	(segment
		(start 370.498116 -264.499852)
		(end 370.497862 -264.500106)
		(width 0.2032)
		(layer "F.Cu")
		(net "GND")
	)
	(segment
		(start 38.315646 -276.366732)
		(end 37.210746 -276.366732)
		(width 0.381)
		(layer "F.Cu")
		(net "GND")
	)
	(segment
		(start 159.918146 -214.316564)
		(end 158.813246 -214.316564)
		(width 0.381)
		(layer "F.Cu")
		(net "GND")
	)
	(segment
		(start 162.913314 -314.616592)
		(end 164.018214 -314.616592)
		(width 0.381)
		(layer "F.Cu")
		(net "GND")
	)
	(segment
		(start 444.472314 -306.116736)
		(end 445.577214 -306.116736)
		(width 0.381)
		(layer "F.Cu")
		(net "GND")
	)
	(segment
		(start 311.882282 -262.76681)
		(end 312.987182 -262.76681)
		(width 0.381)
		(layer "F.Cu")
		(net "GND")
	)
	(segment
		(start 11.135614 -294.216582)
		(end 12.240514 -294.216582)
		(width 0.381)
		(layer "F.Cu")
		(net "GND")
	)
	(segment
		(start 346.063316 -287.288986)
		(end 346.063062 -287.28924)
		(width 0.254)
		(layer "F.Cu")
		(net "GND")
	)
	(segment
		(start 217.82024 -106.967274)
		(end 217.82024 -106.111548)
		(width 0.3556)
		(layer "F.Cu")
		(net "GND")
	)
	(segment
		(start 252.616462 -92.890594)
		(end 253.135892 -92.371164)
		(width 0.3556)
		(layer "F.Cu")
		(net "GND")
	)
	(segment
		(start 382.968754 -347.909896)
		(end 382.299464 -347.909896)
		(width 0.3556)
		(layer "F.Cu")
		(net "GND")
	)
	(segment
		(start 275.268182 -294.216582)
		(end 274.163282 -294.216582)
		(width 0.381)
		(layer "F.Cu")
		(net "GND")
	)
	(segment
		(start 207.071214 -244.066568)
		(end 208.176114 -244.066568)
		(width 0.381)
		(layer "F.Cu")
		(net "GND")
	)
	(segment
		(start 334.864456 -54.089046)
		(end 335.67878 -54.558946)
		(width 0.2032)
		(layer "F.Cu")
		(net "GND")
	)
	(segment
		(start 215.719914 -271.266666)
		(end 216.824814 -271.266666)
		(width 0.381)
		(layer "F.Cu")
		(net "GND")
	)
	(segment
		(start 91.074494 -289.195002)
		(end 91.074494 -289.807142)
		(width 0.2032)
		(layer "F.Cu")
		(net "GND")
	)
	(segment
		(start 139.477496 -254.197612)
		(end 139.510516 -254.164592)
		(width 0.2032)
		(layer "F.Cu")
		(net "GND")
	)
	(segment
		(start 463.659982 -295.916604)
		(end 462.555082 -295.916604)
		(width 0.381)
		(layer "F.Cu")
		(net "GND")
	)
	(segment
		(start 282.811982 -221.116652)
		(end 283.916882 -221.116652)
		(width 0.381)
		(layer "F.Cu")
		(net "GND")
	)
	(segment
		(start 271.168114 -210.916774)
		(end 270.063214 -210.916774)
		(width 0.381)
		(layer "F.Cu")
		(net "GND")
	)
	(segment
		(start 169.352214 -244.066568)
		(end 170.457114 -244.066568)
		(width 0.381)
		(layer "F.Cu")
		(net "GND")
	)
	(segment
		(start 352.171762 -266.405868)
		(end 352.172016 -266.406122)
		(width 0.2032)
		(layer "F.Cu")
		(net "GND")
	)
	(segment
		(start 30.771846 -221.96679)
		(end 31.876746 -221.96679)
		(width 0.381)
		(layer "F.Cu")
		(net "GND")
	)
	(segment
		(start 456.116182 -269.566644)
		(end 455.011282 -269.566644)
		(width 0.381)
		(layer "F.Cu")
		(net "GND")
	)
	(segment
		(start 164.018214 -264.466578)
		(end 162.913314 -264.466578)
		(width 0.381)
		(layer "F.Cu")
		(net "GND")
	)
	(segment
		(start 365.21898 -216.250774)
		(end 365.219234 -216.25052)
		(width 0.254)
		(layer "F.Cu")
		(net "GND")
	)
	(segment
		(start 84.793836 -269.94866)
		(end 84.812378 -269.938754)
		(width 0.2032)
		(layer "F.Cu")
		(net "GND")
	)
	(segment
		(start 422.945814 -290.816792)
		(end 421.840914 -290.816792)
		(width 0.381)
		(layer "F.Cu")
		(net "GND")
	)
	(segment
		(start 348.882716 -268.84757)
		(end 348.882462 -268.847824)
		(width 0.2032)
		(layer "F.Cu")
		(net "GND")
	)
	(segment
		(start 122.558048 -266.127992)
		(end 122.557794 -266.128246)
		(width 0.254)
		(layer "F.Cu")
		(net "GND")
	)
	(segment
		(start 439.49366 -106.78541)
		(end 438.85104 -106.78541)
		(width 0.3556)
		(layer "F.Cu")
		(net "GND")
	)
	(segment
		(start 111.170466 -233.87812)
		(end 111.170212 -233.877866)
		(width 0.2032)
		(layer "F.Cu")
		(net "GND")
	)
	(segment
		(start 19.784314 -196.466714)
		(end 18.679414 -196.466714)
		(width 0.381)
		(layer "F.Cu")
		(net "GND")
	)
	(segment
		(start 435.823614 -263.616694)
		(end 436.928514 -263.616694)
		(width 0.381)
		(layer "F.Cu")
		(net "GND")
	)
	(segment
		(start 433.484782 -249.166634)
		(end 434.589682 -249.166634)
		(width 0.381)
		(layer "F.Cu")
		(net "GND")
	)
	(segment
		(start 119.738648 -281.869896)
		(end 119.738648 -282.405582)
		(width 0.254)
		(layer "F.Cu")
		(net "GND")
	)
	(segment
		(start 441.028582 -314.616592)
		(end 442.133482 -314.616592)
		(width 0.381)
		(layer "F.Cu")
		(net "GND")
	)
	(segment
		(start 165.013894 -236.416596)
		(end 166.357046 -236.416596)
		(width 0.381)
		(layer "F.Cu")
		(net "GND")
	)
	(segment
		(start 194.00393 -106.225848)
		(end 194.61353 -106.225848)
		(width 0.3556)
		(layer "F.Cu")
		(net "GND")
	)
	(segment
		(start 129.606294 -266.405868)
		(end 129.606548 -266.941808)
		(width 0.2032)
		(layer "F.Cu")
		(net "GND")
	)
	(segment
		(start 421.840914 -242.3668)
		(end 422.945814 -242.3668)
		(width 0.381)
		(layer "F.Cu")
		(net "GND")
	)
	(segment
		(start 111.640112 -214.546688)
		(end 111.640366 -214.546434)
		(width 0.254)
		(layer "F.Cu")
		(net "GND")
	)
	(segment
		(start 215.719914 -198.166736)
		(end 216.824814 -198.166736)
		(width 0.381)
		(layer "F.Cu")
		(net "GND")
	)
	(segment
		(start 281.707082 -299.316648)
		(end 282.811982 -299.316648)
		(width 0.381)
		(layer "F.Cu")
		(net "GND")
	)
	(segment
		(start 286.255714 -203.266802)
		(end 287.360614 -203.266802)
		(width 0.381)
		(layer "F.Cu")
		(net "GND")
	)
	(segment
		(start 289.250882 -297.616626)
		(end 290.355782 -297.616626)
		(width 0.381)
		(layer "F.Cu")
		(net "GND")
	)
	(segment
		(start 106.941366 -220.041724)
		(end 106.941366 -219.506038)
		(width 0.254)
		(layer "F.Cu")
		(net "GND")
	)
	(segment
		(start 384.485134 -217.600276)
		(end 384.485134 -217.064336)
		(width 0.2032)
		(layer "F.Cu")
		(net "GND")
	)
	(segment
		(start 459.559914 -242.3668)
		(end 458.455014 -242.3668)
		(width 0.381)
		(layer "F.Cu")
		(net "GND")
	)
	(segment
		(start 383.07518 -237.947454)
		(end 383.07518 -237.411768)
		(width 0.254)
		(layer "F.Cu")
		(net "GND")
	)
	(segment
		(start 7.035546 -279.766776)
		(end 8.140446 -279.766776)
		(width 0.381)
		(layer "F.Cu")
		(net "GND")
	)
	(segment
		(start 355.82098 -226.553268)
		(end 355.82098 -226.017582)
		(width 0.254)
		(layer "F.Cu")
		(net "GND")
	)
	(segment
		(start 347.473016 -268.034008)
		(end 347.473016 -268.569694)
		(width 0.2032)
		(layer "F.Cu")
		(net "GND")
	)
	(segment
		(start 371.79758 -216.78646)
		(end 371.79758 -216.250774)
		(width 0.254)
		(layer "F.Cu")
		(net "GND")
	)
	(segment
		(start 27.328114 -213.46668)
		(end 28.433014 -213.46668)
		(width 0.381)
		(layer "F.Cu")
		(net "GND")
	)
	(segment
		(start 374.257316 -275.35886)
		(end 374.257062 -275.8948)
		(width 0.2032)
		(layer "F.Cu")
		(net "GND")
	)
	(segment
		(start 189.26302 -16.551148)
		(end 189.262004 -16.550132)
		(width 0.3556)
		(layer "F.Cu")
		(net "GND")
	)
	(segment
		(start 421.840914 -258.516628)
		(end 422.945814 -258.516628)
		(width 0.381)
		(layer "F.Cu")
		(net "GND")
	)
	(segment
		(start 200.632314 -205.816708)
		(end 201.737214 -205.816708)
		(width 0.381)
		(layer "F.Cu")
		(net "GND")
	)
	(segment
		(start 384.015234 -229.808786)
		(end 384.015234 -229.272846)
		(width 0.254)
		(layer "F.Cu")
		(net "GND")
	)
	(segment
		(start 421.840914 -306.116736)
		(end 420.736014 -306.116736)
		(width 0.381)
		(layer "F.Cu")
		(net "GND")
	)
	(segment
		(start 429.384714 -289.11677)
		(end 430.489614 -289.11677)
		(width 0.381)
		(layer "F.Cu")
		(net "GND")
	)
	(segment
		(start 157.708346 -290.816792)
		(end 158.813246 -290.816792)
		(width 0.381)
		(layer "F.Cu")
		(net "GND")
	)
	(segment
		(start 166.357046 -251.716794)
		(end 167.461946 -251.716794)
		(width 0.381)
		(layer "F.Cu")
		(net "GND")
	)
	(segment
		(start 372.377716 -272.103342)
		(end 372.377462 -272.639282)
		(width 0.2032)
		(layer "F.Cu")
		(net "GND")
	)
	(segment
		(start 410.853382 -261.066788)
		(end 411.958282 -261.066788)
		(width 0.381)
		(layer "F.Cu")
		(net "GND")
	)
	(segment
		(start 107.521248 -288.381186)
		(end 107.521248 -288.917126)
		(width 0.254)
		(layer "F.Cu")
		(net "GND")
	)
	(segment
		(start 120.098312 -223.297496)
		(end 120.098312 -222.76181)
		(width 0.254)
		(layer "F.Cu")
		(net "GND")
	)
	(segment
		(start 298.396406 -424.507152)
		(end 298.396406 -424.95597)
		(width 0.3556)
		(layer "F.Cu")
		(net "GND")
	)
	(segment
		(start 204.076046 -300.166786)
		(end 205.180946 -300.166786)
		(width 0.381)
		(layer "F.Cu")
		(net "GND")
	)
	(segment
		(start 196.532246 -204.96657)
		(end 197.637146 -204.96657)
		(width 0.381)
		(layer "F.Cu")
		(net "GND")
	)
	(segment
		(start 38.315646 -317.166752)
		(end 37.210746 -317.166752)
		(width 0.381)
		(layer "F.Cu")
		(net "GND")
	)
	(segment
		(start 204.076046 -272.116804)
		(end 205.180946 -272.116804)
		(width 0.381)
		(layer "F.Cu")
		(net "GND")
	)
	(segment
		(start 376.49658 -242.295172)
		(end 376.496834 -242.294918)
		(width 0.2032)
		(layer "F.Cu")
		(net "GND")
	)
	(segment
		(start 101.882448 -273.730974)
		(end 101.882448 -274.26666)
		(width 0.254)
		(layer "F.Cu")
		(net "GND")
	)
	(segment
		(start 121.038112 -220.041978)
		(end 121.038366 -220.041724)
		(width 0.254)
		(layer "F.Cu")
		(net "GND")
	)
	(segment
		(start 127.257048 -287.288986)
		(end 127.256794 -287.28924)
		(width 0.254)
		(layer "F.Cu")
		(net "GND")
	)
	(segment
		(start 119.628666 -217.600276)
		(end 119.628666 -217.064336)
		(width 0.254)
		(layer "F.Cu")
		(net "GND")
	)
	(segment
		(start 336.195162 -263.150604)
		(end 336.195162 -263.686544)
		(width 0.254)
		(layer "F.Cu")
		(net "GND")
	)
	(segment
		(start 58.608214 -233.86669)
		(end 57.503314 -233.86669)
		(width 0.381)
		(layer "F.Cu")
		(net "GND")
	)
	(segment
		(start 307.566314 -217.716608)
		(end 308.887114 -217.716608)
		(width 0.381)
		(layer "F.Cu")
		(net "GND")
	)
	(segment
		(start 344.63355 -41.871646)
		(end 344.619326 -41.847008)
		(width 0.254)
		(layer "F.Cu")
		(net "GND")
	)
	(segment
		(start 410.853382 -239.81664)
		(end 409.748482 -239.81664)
		(width 0.381)
		(layer "F.Cu")
		(net "GND")
	)
	(segment
		(start 29.666946 -285.716726)
		(end 30.771846 -285.716726)
		(width 0.381)
		(layer "F.Cu")
		(net "GND")
	)
	(segment
		(start 115.869212 -232.250234)
		(end 115.869212 -231.714548)
		(width 0.2032)
		(layer "F.Cu")
		(net "GND")
	)
	(segment
		(start 296.794682 -303.566576)
		(end 297.899582 -303.566576)
		(width 0.381)
		(layer "F.Cu")
		(net "GND")
	)
	(segment
		(start 368.148362 -279.96388)
		(end 368.148616 -279.964134)
		(width 0.254)
		(layer "F.Cu")
		(net "GND")
	)
	(segment
		(start 413.192214 -225.36658)
		(end 414.297114 -225.36658)
		(width 0.381)
		(layer "F.Cu")
		(net "GND")
	)
	(segment
		(start 375.666762 -259.894832)
		(end 375.666762 -260.430518)
		(width 0.254)
		(layer "F.Cu")
		(net "GND")
	)
	(segment
		(start 420.736014 -265.316716)
		(end 421.840914 -265.316716)
		(width 0.381)
		(layer "F.Cu")
		(net "GND")
	)
	(segment
		(start 261.285482 -215.166702)
		(end 260.180582 -215.166702)
		(width 0.381)
		(layer "F.Cu")
		(net "GND")
	)
	(segment
		(start 34.871914 -205.816708)
		(end 35.976814 -205.816708)
		(width 0.381)
		(layer "F.Cu")
		(net "GND")
	)
	(segment
		(start 341.098378 -42.341546)
		(end 341.276432 -42.649648)
		(width 0.2032)
		(layer "F.Cu")
		(net "GND")
	)
	(segment
		(start 134.305294 -282.683966)
		(end 134.305548 -282.68422)
		(width 0.254)
		(layer "F.Cu")
		(net "GND")
	)
	(segment
		(start 110.230666 -234.97032)
		(end 110.23092 -234.970066)
		(width 0.254)
		(layer "F.Cu")
		(net "GND")
	)
	(segment
		(start 109.029246 -92.365576)
		(end 109.729524 -92.365576)
		(width 0.3556)
		(layer "F.Cu")
		(net "GND")
	)
	(segment
		(start 19.784314 -312.91657)
		(end 20.889214 -312.91657)
		(width 0.381)
		(layer "F.Cu")
		(net "GND")
	)
	(segment
		(start 352.062034 -220.041724)
		(end 352.062034 -219.506038)
		(width 0.254)
		(layer "F.Cu")
		(net "GND")
	)
	(segment
		(start 382.715516 -285.6611)
		(end 382.715262 -285.661354)
		(width 0.2032)
		(layer "F.Cu")
		(net "GND")
	)
	(segment
		(start 433.484782 -194.766692)
		(end 434.589682 -194.766692)
		(width 0.381)
		(layer "F.Cu")
		(net "GND")
	)
	(segment
		(start 370.968016 -282.68422)
		(end 370.968016 -283.219906)
		(width 0.254)
		(layer "F.Cu")
		(net "GND")
	)
	(segment
		(start 85.40496 -37.500052)
		(end 85.40496 -38.287452)
		(width 0.3556)
		(layer "F.Cu")
		(net "GND")
	)
	(segment
		(start 38.315646 -234.716574)
		(end 37.210746 -234.716574)
		(width 0.381)
		(layer "F.Cu")
		(net "GND")
	)
	(segment
		(start 173.900846 -309.51678)
		(end 175.005746 -309.51678)
		(width 0.381)
		(layer "F.Cu")
		(net "GND")
	)
	(segment
		(start 15.684246 -283.166566)
		(end 16.789146 -283.166566)
		(width 0.381)
		(layer "F.Cu")
		(net "GND")
	)
	(segment
		(start 27.328114 -241.516662)
		(end 28.433014 -241.516662)
		(width 0.381)
		(layer "F.Cu")
		(net "GND")
	)
	(segment
		(start 23.228046 -313.766708)
		(end 24.332946 -313.766708)
		(width 0.381)
		(layer "F.Cu")
		(net "GND")
	)
	(segment
		(start 127.726694 -261.522718)
		(end 127.726694 -262.058404)
		(width 0.254)
		(layer "F.Cu")
		(net "GND")
	)
	(segment
		(start 345.593162 -253.383796)
		(end 345.593162 -253.919482)
		(width 0.2032)
		(layer "F.Cu")
		(net "GND")
	)
	(segment
		(start 43.520614 -295.916604)
		(end 42.415714 -295.916604)
		(width 0.381)
		(layer "F.Cu")
		(net "GND")
	)
	(segment
		(start 173.900846 -233.016806)
		(end 172.795946 -233.016806)
		(width 0.381)
		(layer "F.Cu")
		(net "GND")
	)
	(segment
		(start 436.928514 -236.416596)
		(end 438.033414 -236.416596)
		(width 0.381)
		(layer "F.Cu")
		(net "GND")
	)
	(segment
		(start 405.648414 -201.56678)
		(end 406.753314 -201.56678)
		(width 0.381)
		(layer "F.Cu")
		(net "GND")
	)
	(segment
		(start 101.882448 -280.77795)
		(end 101.882194 -280.778204)
		(width 0.2032)
		(layer "F.Cu")
		(net "GND")
	)
	(segment
		(start 200.632314 -235.566712)
		(end 201.737214 -235.566712)
		(width 0.381)
		(layer "F.Cu")
		(net "GND")
	)
	(segment
		(start 344.619326 -41.847008)
		(end 344.363294 -41.401492)
		(width 0.254)
		(layer "F.Cu")
		(net "GND")
	)
	(segment
		(start 138.424666 -248.528078)
		(end 139.062206 -248.528078)
		(width 0.2032)
		(layer "F.Cu")
		(net "GND")
	)
	(segment
		(start 365.983266 -338.60359)
		(end 365.708184 -338.328508)
		(width 0.381)
		(layer "F.Cu")
		(net "GND")
	)
	(segment
		(start 187.883546 -283.166566)
		(end 188.988446 -283.166566)
		(width 0.381)
		(layer "F.Cu")
		(net "GND")
	)
	(segment
		(start 202.971146 -244.916706)
		(end 204.076046 -244.916706)
		(width 0.381)
		(layer "F.Cu")
		(net "GND")
	)
	(segment
		(start 463.659982 -207.51673)
		(end 464.764882 -207.51673)
		(width 0.381)
		(layer "F.Cu")
		(net "GND")
	)
	(segment
		(start 436.928514 -233.016806)
		(end 438.033414 -233.016806)
		(width 0.381)
		(layer "F.Cu")
		(net "GND")
	)
	(segment
		(start 349.242634 -236.319568)
		(end 349.242634 -235.783882)
		(width 0.2032)
		(layer "F.Cu")
		(net "GND")
	)
	(segment
		(start 90.964766 -234.691936)
		(end 90.964766 -234.15625)
		(width 0.254)
		(layer "F.Cu")
		(net "GND")
	)
	(segment
		(start 214.615014 -247.466612)
		(end 215.719914 -247.466612)
		(width 0.381)
		(layer "F.Cu")
		(net "GND")
	)
	(segment
		(start 346.063316 -254.197612)
		(end 346.063316 -254.733552)
		(width 0.2032)
		(layer "F.Cu")
		(net "GND")
	)
	(segment
		(start 414.297114 -212.616796)
		(end 415.402014 -212.616796)
		(width 0.381)
		(layer "F.Cu")
		(net "GND")
	)
	(segment
		(start 118.35765 -333.763112)
		(end 118.35765 -333.330804)
		(width 0.2032)
		(layer "F.Cu")
		(net "GND")
	)
	(segment
		(start 20.889214 -221.116652)
		(end 19.784314 -221.116652)
		(width 0.381)
		(layer "F.Cu")
		(net "GND")
	)
	(segment
		(start 375.087134 -214.344758)
		(end 375.087134 -213.732618)
		(width 0.254)
		(layer "F.Cu")
		(net "GND")
	)
	(segment
		(start 130.853942 -97.81159)
		(end 130.853942 -97.13087)
		(width 0.254)
		(layer "F.Cu")
		(net "GND")
	)
	(segment
		(start 274.29841 -93.741494)
		(end 273.62658 -93.741494)
		(width 0.3556)
		(layer "F.Cu")
		(net "GND")
	)
	(segment
		(start 185.544714 -213.46668)
		(end 186.649614 -213.46668)
		(width 0.381)
		(layer "F.Cu")
		(net "GND")
	)
	(segment
		(start 198.77913 -113.824258)
		(end 198.10476 -114.498628)
		(width 0.3556)
		(layer "F.Cu")
		(net "GND")
	)
	(segment
		(start 376.966734 -246.900446)
		(end 376.966734 -246.364506)
		(width 0.2032)
		(layer "F.Cu")
		(net "GND")
	)
	(segment
		(start 456.116182 -210.066636)
		(end 455.011282 -210.066636)
		(width 0.381)
		(layer "F.Cu")
		(net "GND")
	)
	(segment
		(start 435.823614 -309.51678)
		(end 436.928514 -309.51678)
		(width 0.381)
		(layer "F.Cu")
		(net "GND")
	)
	(segment
		(start 297.096434 -423.05605)
		(end 297.096434 -423.56532)
		(width 0.3556)
		(layer "F.Cu")
		(net "GND")
	)
	(segment
		(start 86.265766 -218.414346)
		(end 86.265766 -217.87866)
		(width 0.2032)
		(layer "F.Cu")
		(net "GND")
	)
	(segment
		(start 276.373082 -299.316648)
		(end 275.268182 -299.316648)
		(width 0.381)
		(layer "F.Cu")
		(net "GND")
	)
	(segment
		(start 39.420546 -272.116804)
		(end 38.315646 -272.116804)
		(width 0.381)
		(layer "F.Cu")
		(net "GND")
	)
	(segment
		(start 427.045882 -295.916604)
		(end 425.940982 -295.916604)
		(width 0.381)
		(layer "F.Cu")
		(net "GND")
	)
	(segment
		(start 89.555066 -228.99497)
		(end 89.555066 -228.459284)
		(width 0.2032)
		(layer "F.Cu")
		(net "GND")
	)
	(segment
		(start 281.707082 -297.616626)
		(end 282.811982 -297.616626)
		(width 0.381)
		(layer "F.Cu")
		(net "GND")
	)
	(segment
		(start 37.965888 -127.71374)
		(end 37.356288 -127.71374)
		(width 0.381)
		(layer "F.Cu")
		(net "GND")
	)
	(segment
		(start 29.666946 -231.316784)
		(end 30.771846 -231.316784)
		(width 0.381)
		(layer "F.Cu")
		(net "GND")
	)
	(segment
		(start 433.484782 -228.766624)
		(end 434.589682 -228.766624)
		(width 0.381)
		(layer "F.Cu")
		(net "GND")
	)
	(segment
		(start 63.942214 -294.216582)
		(end 65.047114 -294.216582)
		(width 0.381)
		(layer "F.Cu")
		(net "GND")
	)
	(segment
		(start 272.273014 -279.766776)
		(end 271.168114 -279.766776)
		(width 0.381)
		(layer "F.Cu")
		(net "GND")
	)
	(segment
		(start 173.900846 -197.316598)
		(end 172.795946 -197.316598)
		(width 0.381)
		(layer "F.Cu")
		(net "GND")
	)
	(segment
		(start 288.180018 -395.046454)
		(end 287.564068 -395.046454)
		(width 0.3556)
		(layer "F.Cu")
		(net "GND")
	)
	(segment
		(start 452.016114 -290.816792)
		(end 450.911214 -290.816792)
		(width 0.381)
		(layer "F.Cu")
		(net "GND")
	)
	(segment
		(start 420.736014 -242.3668)
		(end 421.840914 -242.3668)
		(width 0.381)
		(layer "F.Cu")
		(net "GND")
	)
	(segment
		(start 335.615534 -233.87812)
		(end 335.615534 -233.34218)
		(width 0.254)
		(layer "F.Cu")
		(net "GND")
	)
	(segment
		(start 181.444646 -272.116804)
		(end 180.339746 -272.116804)
		(width 0.381)
		(layer "F.Cu")
		(net "GND")
	)
	(segment
		(start 39.420546 -197.316598)
		(end 38.315646 -197.316598)
		(width 0.381)
		(layer "F.Cu")
		(net "GND")
	)
	(segment
		(start 267.724382 -258.516628)
		(end 268.829282 -258.516628)
		(width 0.381)
		(layer "F.Cu")
		(net "GND")
	)
	(segment
		(start 459.559914 -223.666558)
		(end 458.455014 -223.666558)
		(width 0.381)
		(layer "F.Cu")
		(net "GND")
	)
	(segment
		(start 275.268182 -250.866656)
		(end 274.163282 -250.866656)
		(width 0.381)
		(layer "F.Cu")
		(net "GND")
	)
	(segment
		(start 432.379882 -308.666642)
		(end 433.484782 -308.666642)
		(width 0.381)
		(layer "F.Cu")
		(net "GND")
	)
	(segment
		(start 145.128742 -33.157668)
		(end 144.188942 -33.157668)
		(width 0.3556)
		(layer "F.Cu")
		(net "GND")
	)
	(segment
		(start 8.140446 -301.866808)
		(end 9.245346 -301.866808)
		(width 0.381)
		(layer "F.Cu")
		(net "GND")
	)
	(segment
		(start 278.246078 -416.323018)
		(end 278.294846 -416.27425)
		(width 0.3556)
		(layer "F.Cu")
		(net "GND")
	)
	(segment
		(start 197.637146 -276.366732)
		(end 196.532246 -276.366732)
		(width 0.381)
		(layer "F.Cu")
		(net "GND")
	)
	(segment
		(start 413.192214 -210.916774)
		(end 414.297114 -210.916774)
		(width 0.381)
		(layer "F.Cu")
		(net "GND")
	)
	(segment
		(start 98.123248 -270.475456)
		(end 98.123248 -271.011142)
		(width 0.2032)
		(layer "F.Cu")
		(net "GND")
	)
	(segment
		(start 325.982838 -51.32959)
		(end 326.87768 -51.32959)
		(width 0.2032)
		(layer "F.Cu")
		(net "GND")
	)
	(segment
		(start 110.340648 -274.26666)
		(end 110.340394 -274.266914)
		(width 0.254)
		(layer "F.Cu")
		(net "GND")
	)
	(segment
		(start 429.384714 -231.316784)
		(end 430.489614 -231.316784)
		(width 0.381)
		(layer "F.Cu")
		(net "GND")
	)
	(segment
		(start 90.964766 -244.45849)
		(end 90.964766 -243.922804)
		(width 0.2032)
		(layer "F.Cu")
		(net "GND")
	)
	(segment
		(start 261.285482 -204.116686)
		(end 260.180582 -204.116686)
		(width 0.381)
		(layer "F.Cu")
		(net "GND")
	)
	(segment
		(start 181.444646 -298.466764)
		(end 180.339746 -298.466764)
		(width 0.381)
		(layer "F.Cu")
		(net "GND")
	)
	(segment
		(start 422.945814 -272.116804)
		(end 421.840914 -272.116804)
		(width 0.381)
		(layer "F.Cu")
		(net "GND")
	)
	(segment
		(start 100.942648 -286.7533)
		(end 100.942648 -287.288986)
		(width 0.254)
		(layer "F.Cu")
		(net "GND")
	)
	(segment
		(start 456.116182 -196.466714)
		(end 455.011282 -196.466714)
		(width 0.381)
		(layer "F.Cu")
		(net "GND")
	)
	(segment
		(start 57.503314 -233.86669)
		(end 56.398414 -233.86669)
		(width 0.381)
		(layer "F.Cu")
		(net "GND")
	)
	(segment
		(start 340.78418 -241.203226)
		(end 340.784434 -241.202972)
		(width 0.2032)
		(layer "F.Cu")
		(net "GND")
	)
	(segment
		(start 305.443382 -219.41663)
		(end 306.764182 -219.41663)
		(width 0.381)
		(layer "F.Cu")
		(net "GND")
	)
	(segment
		(start 293.799514 -231.316784)
		(end 292.694614 -231.316784)
		(width 0.381)
		(layer "F.Cu")
		(net "GND")
	)
	(segment
		(start 371.907562 -281.591512)
		(end 371.907816 -281.591766)
		(width 0.254)
		(layer "F.Cu")
		(net "GND")
	)
	(segment
		(start 139.706096 -94.887542)
		(end 139.706096 -93.757242)
		(width 0.3556)
		(layer "F.Cu")
		(net "GND")
	)
	(segment
		(start 112.110266 -224.111566)
		(end 112.110266 -223.575626)
		(width 0.2032)
		(layer "F.Cu")
		(net "GND")
	)
	(segment
		(start 194.193414 -204.116686)
		(end 193.088514 -204.116686)
		(width 0.381)
		(layer "F.Cu")
		(net "GND")
	)
	(segment
		(start 179.105814 -205.816708)
		(end 178.000914 -205.816708)
		(width 0.381)
		(layer "F.Cu")
		(net "GND")
	)
	(segment
		(start 178.000914 -289.966654)
		(end 179.105814 -289.966654)
		(width 0.381)
		(layer "F.Cu")
		(net "GND")
	)
	(segment
		(start 348.882716 -275.35886)
		(end 348.882716 -275.8948)
		(width 0.254)
		(layer "F.Cu")
		(net "GND")
	)
	(segment
		(start 382.715516 -286.7533)
		(end 382.715516 -287.288986)
		(width 0.254)
		(layer "F.Cu")
		(net "GND")
	)
	(segment
		(start 424.836082 -235.566712)
		(end 425.940982 -235.566712)
		(width 0.381)
		(layer "F.Cu")
		(net "GND")
	)
	(segment
		(start 194.193414 -249.166634)
		(end 193.088514 -249.166634)
		(width 0.381)
		(layer "F.Cu")
		(net "GND")
	)
	(segment
		(start 327.41489 -57.954926)
		(end 327.240138 -58.609992)
		(width 0.2032)
		(layer "F.Cu")
		(net "GND")
	)
	(segment
		(start 122.917712 -231.436418)
		(end 122.917966 -231.436164)
		(width 0.254)
		(layer "F.Cu")
		(net "GND")
	)
	(segment
		(start 421.840914 -206.666592)
		(end 422.945814 -206.666592)
		(width 0.381)
		(layer "F.Cu")
		(net "GND")
	)
	(segment
		(start 42.415714 -264.466578)
		(end 41.310814 -264.466578)
		(width 0.381)
		(layer "F.Cu")
		(net "GND")
	)
	(segment
		(start 8.140446 -273.816572)
		(end 7.035546 -273.816572)
		(width 0.381)
		(layer "F.Cu")
		(net "GND")
	)
	(segment
		(start 200.632314 -228.766624)
		(end 201.737214 -228.766624)
		(width 0.381)
		(layer "F.Cu")
		(net "GND")
	)
	(segment
		(start 267.724382 -239.81664)
		(end 268.829282 -239.81664)
		(width 0.381)
		(layer "F.Cu")
		(net "GND")
	)
	(segment
		(start 94.364048 -278.614378)
		(end 94.364048 -279.150318)
		(width 0.254)
		(layer "F.Cu")
		(net "GND")
	)
	(segment
		(start 216.788238 -20.569682)
		(end 216.788238 -23.017988)
		(width 0.3556)
		(layer "F.Cu")
		(net "GND")
	)
	(segment
		(start 136.184894 -257.175254)
		(end 136.184894 -256.639314)
		(width 0.2032)
		(layer "F.Cu")
		(net "GND")
	)
	(segment
		(start 180.339746 -212.616796)
		(end 181.444646 -212.616796)
		(width 0.381)
		(layer "F.Cu")
		(net "GND")
	)
	(segment
		(start 8.140446 -304.416714)
		(end 9.245346 -304.416714)
		(width 0.381)
		(layer "F.Cu")
		(net "GND")
	)
	(segment
		(start 134.195566 -240.667286)
		(end 134.195566 -241.203226)
		(width 0.2032)
		(layer "F.Cu")
		(net "GND")
	)
	(segment
		(start 406.753314 -278.066754)
		(end 407.858214 -278.066754)
		(width 0.381)
		(layer "F.Cu")
		(net "GND")
	)
	(segment
		(start 169.267124 -17.655032)
		(end 169.267124 -16.550132)
		(width 0.3556)
		(layer "F.Cu")
		(net "GND")
	)
	(segment
		(start 23.228046 -201.56678)
		(end 24.332946 -201.56678)
		(width 0.381)
		(layer "F.Cu")
		(net "GND")
	)
	(segment
		(start 90.494866 -250.155964)
		(end 90.494866 -249.620024)
		(width 0.2032)
		(layer "F.Cu")
		(net "GND")
	)
	(segment
		(start 337.900264 -39.295324)
		(end 336.899758 -39.295324)
		(width 0.2032)
		(layer "F.Cu")
		(net "GND")
	)
	(segment
		(start 19.784314 -280.61666)
		(end 20.889214 -280.61666)
		(width 0.381)
		(layer "F.Cu")
		(net "GND")
	)
	(segment
		(start 457.221082 -215.166702)
		(end 456.116182 -215.166702)
		(width 0.381)
		(layer "F.Cu")
		(net "GND")
	)
	(segment
		(start 110.230666 -248.528078)
		(end 110.23092 -248.527824)
		(width 0.254)
		(layer "F.Cu")
		(net "GND")
	)
	(segment
		(start 406.753314 -236.416596)
		(end 405.395938 -236.416596)
		(width 0.381)
		(layer "F.Cu")
		(net "GND")
	)
	(segment
		(start 207.071214 -204.116686)
		(end 208.176114 -204.116686)
		(width 0.381)
		(layer "F.Cu")
		(net "GND")
	)
	(segment
		(start 132.315712 -249.342148)
		(end 132.315966 -249.341894)
		(width 0.2032)
		(layer "F.Cu")
		(net "GND")
	)
	(segment
		(start 84.856066 -228.99497)
		(end 84.386166 -229.272846)
		(width 0.2032)
		(layer "F.Cu")
		(net "GND")
	)
	(segment
		(start 113.519712 -223.297496)
		(end 113.519712 -222.76181)
		(width 0.254)
		(layer "F.Cu")
		(net "GND")
	)
	(segment
		(start 380.365762 -281.591512)
		(end 380.366016 -281.591766)
		(width 0.254)
		(layer "F.Cu")
		(net "GND")
	)
	(segment
		(start 119.249952 -410.129228)
		(end 119.249952 -411.120082)
		(width 0.3556)
		(layer "F.Cu")
		(net "GND")
	)
	(segment
		(start 441.129166 -125.46584)
		(end 441.099194 -125.435868)
		(width 0.381)
		(layer "F.Cu")
		(net "GND")
	)
	(segment
		(start 113.67008 -122.532648)
		(end 113.67008 -123.148598)
		(width 0.3556)
		(layer "F.Cu")
		(net "GND")
	)
	(segment
		(start 459.559914 -298.466764)
		(end 460.664814 -298.466764)
		(width 0.381)
		(layer "F.Cu")
		(net "GND")
	)
	(segment
		(start 435.823614 -201.56678)
		(end 436.928514 -201.56678)
		(width 0.381)
		(layer "F.Cu")
		(net "GND")
	)
	(segment
		(start 138.424666 -240.389156)
		(end 137.484866 -240.389156)
		(width 0.254)
		(layer "F.Cu")
		(net "GND")
	)
	(segment
		(start 367.483644 -408.71521)
		(end 367.878868 -408.319986)
		(width 0.3556)
		(layer "F.Cu")
		(net "GND")
	)
	(segment
		(start 448.572382 -280.61666)
		(end 447.467482 -280.61666)
		(width 0.381)
		(layer "F.Cu")
		(net "GND")
	)
	(segment
		(start 444.472314 -227.066602)
		(end 445.577214 -227.066602)
		(width 0.381)
		(layer "F.Cu")
		(net "GND")
	)
	(segment
		(start 53.403246 -301.866808)
		(end 52.298346 -301.866808)
		(width 0.381)
		(layer "F.Cu")
		(net "GND")
	)
	(segment
		(start 135.14705 -14.705076)
		(end 135.14705 -13.600176)
		(width 0.3556)
		(layer "F.Cu")
		(net "GND")
	)
	(segment
		(start 328.244962 -52.952396)
		(end 328.194162 -53.003196)
		(width 0.2032)
		(layer "F.Cu")
		(net "GND")
	)
	(segment
		(start 337.495134 -224.111566)
		(end 337.495134 -223.57588)
		(width 0.254)
		(layer "F.Cu")
		(net "GND")
	)
	(segment
		(start 208.176114 -294.216582)
		(end 209.281014 -294.216582)
		(width 0.381)
		(layer "F.Cu")
		(net "GND")
	)
	(segment
		(start 127.616966 -241.202972)
		(end 127.616966 -240.667286)
		(width 0.2032)
		(layer "F.Cu")
		(net "GND")
	)
	(segment
		(start 169.352214 -271.266666)
		(end 170.457114 -271.266666)
		(width 0.381)
		(layer "F.Cu")
		(net "GND")
	)
	(segment
		(start 260.180582 -205.816708)
		(end 259.075682 -205.816708)
		(width 0.381)
		(layer "F.Cu")
		(net "GND")
	)
	(segment
		(start 425.940982 -286.56661)
		(end 424.836082 -286.56661)
		(width 0.381)
		(layer "F.Cu")
		(net "GND")
	)
	(segment
		(start 77.55509 -342.962992)
		(end 77.55509 -342.5317)
		(width 0.2032)
		(layer "F.Cu")
		(net "GND")
	)
	(segment
		(start 432.379882 -266.1666)
		(end 433.484782 -266.1666)
		(width 0.381)
		(layer "F.Cu")
		(net "GND")
	)
	(segment
		(start 207.071214 -224.516696)
		(end 208.176114 -224.516696)
		(width 0.381)
		(layer "F.Cu")
		(net "GND")
	)
	(segment
		(start 88.725248 -257.988816)
		(end 88.724994 -257.98907)
		(width 0.2032)
		(layer "F.Cu")
		(net "GND")
	)
	(segment
		(start 136.075166 -241.203226)
		(end 136.075166 -240.667286)
		(width 0.254)
		(layer "F.Cu")
		(net "GND")
	)
	(segment
		(start 124.327666 -227.367084)
		(end 124.327666 -226.831144)
		(width 0.2032)
		(layer "F.Cu")
		(net "GND")
	)
	(segment
		(start 360.51998 -226.017582)
		(end 360.520234 -226.017328)
		(width 0.254)
		(layer "F.Cu")
		(net "GND")
	)
	(segment
		(start 368.618516 -264.499852)
		(end 368.618262 -264.500106)
		(width 0.2032)
		(layer "F.Cu")
		(net "GND")
	)
	(segment
		(start 113.629694 -256.639314)
		(end 113.629694 -257.175254)
		(width 0.254)
		(layer "F.Cu")
		(net "GND")
	)
	(segment
		(start 18.679414 -235.566712)
		(end 19.784314 -235.566712)
		(width 0.381)
		(layer "F.Cu")
		(net "GND")
	)
	(segment
		(start 373.317516 -276.986492)
		(end 373.317516 -277.522432)
		(width 0.2032)
		(layer "F.Cu")
		(net "GND")
	)
	(segment
		(start 348.882716 -265.592306)
		(end 348.882462 -265.592306)
		(width 0.254)
		(layer "F.Cu")
		(net "GND")
	)
	(segment
		(start 102.352094 -289.195002)
		(end 102.352094 -289.807142)
		(width 0.2032)
		(layer "F.Cu")
		(net "GND")
	)
	(segment
		(start 254.975614 -309.51678)
		(end 256.080514 -309.51678)
		(width 0.381)
		(layer "F.Cu")
		(net "GND")
	)
	(segment
		(start 457.221082 -210.066636)
		(end 456.116182 -210.066636)
		(width 0.381)
		(layer "F.Cu")
		(net "GND")
	)
	(segment
		(start 376.966734 -228.99497)
		(end 376.96648 -228.994716)
		(width 0.2032)
		(layer "F.Cu")
		(net "GND")
	)
	(segment
		(start 193.088514 -306.96662)
		(end 194.193414 -306.96662)
		(width 0.381)
		(layer "F.Cu")
		(net "GND")
	)
	(segment
		(start 448.572382 -202.416664)
		(end 447.467482 -202.416664)
		(width 0.381)
		(layer "F.Cu")
		(net "GND")
	)
	(segment
		(start 52.894738 -335.477612)
		(end 53.835046 -335.477612)
		(width 0.508)
		(layer "F.Cu")
		(net "GND")
	)
	(segment
		(start 125.847094 -279.428194)
		(end 125.847348 -279.964134)
		(width 0.254)
		(layer "F.Cu")
		(net "GND")
	)
	(segment
		(start 99.383342 -414.371536)
		(end 98.6028 -414.371536)
		(width 0.3556)
		(layer "F.Cu")
		(net "GND")
	)
	(segment
		(start 49.755552 -146.950684)
		(end 49.755552 -147.592034)
		(width 0.381)
		(layer "F.Cu")
		(net "GND")
	)
	(segment
		(start 460.664814 -251.716794)
		(end 459.559914 -251.716794)
		(width 0.381)
		(layer "F.Cu")
		(net "GND")
	)
	(segment
		(start 459.559914 -260.21665)
		(end 458.455014 -260.21665)
		(width 0.381)
		(layer "F.Cu")
		(net "GND")
	)
	(segment
		(start 34.871914 -267.866622)
		(end 33.767014 -267.866622)
		(width 0.381)
		(layer "F.Cu")
		(net "GND")
	)
	(segment
		(start 342.773762 -263.150604)
		(end 342.773762 -263.686544)
		(width 0.2032)
		(layer "F.Cu")
		(net "GND")
	)
	(segment
		(start 343.713562 -279.428194)
		(end 343.713562 -279.96388)
		(width 0.254)
		(layer "F.Cu")
		(net "GND")
	)
	(segment
		(start 330.396596 -58.020204)
		(end 330.396596 -58.850276)
		(width 0.2032)
		(layer "F.Cu")
		(net "GND")
	)
	(segment
		(start 419.502082 -244.066568)
		(end 418.397182 -244.066568)
		(width 0.381)
		(layer "F.Cu")
		(net "GND")
	)
	(segment
		(start 180.555646 -111.375444)
		(end 180.955696 -110.975394)
		(width 0.3556)
		(layer "F.Cu")
		(net "GND")
	)
	(segment
		(start 294.904414 -261.916672)
		(end 293.799514 -261.916672)
		(width 0.381)
		(layer "F.Cu")
		(net "GND")
	)
	(segment
		(start 439.923682 -271.266666)
		(end 441.028582 -271.266666)
		(width 0.381)
		(layer "F.Cu")
		(net "GND")
	)
	(segment
		(start 99.063048 -287.288986)
		(end 99.062794 -287.28924)
		(width 0.254)
		(layer "F.Cu")
		(net "GND")
	)
	(segment
		(start 463.659982 -250.866656)
		(end 464.764882 -250.866656)
		(width 0.381)
		(layer "F.Cu")
		(net "GND")
	)
	(segment
		(start 26.18232 -127.348996)
		(end 26.63825 -127.348996)
		(width 0.381)
		(layer "F.Cu")
		(net "GND")
	)
	(segment
		(start 53.403246 -267.016738)
		(end 52.298346 -267.016738)
		(width 0.3556)
		(layer "F.Cu")
		(net "GND")
	)
	(segment
		(start 214.615014 -207.51673)
		(end 215.719914 -207.51673)
		(width 0.381)
		(layer "F.Cu")
		(net "GND")
	)
	(segment
		(start 453.121014 -313.766708)
		(end 452.016114 -313.766708)
		(width 0.381)
		(layer "F.Cu")
		(net "GND")
	)
	(segment
		(start 112.110266 -227.367084)
		(end 112.110266 -226.831144)
		(width 0.2032)
		(layer "F.Cu")
		(net "GND")
	)
	(segment
		(start 92.014294 -279.96388)
		(end 92.014548 -279.964134)
		(width 0.254)
		(layer "F.Cu")
		(net "GND")
	)
	(segment
		(start 207.071214 -200.716642)
		(end 208.176114 -200.716642)
		(width 0.381)
		(layer "F.Cu")
		(net "GND")
	)
	(segment
		(start 134.305294 -284.311598)
		(end 134.305548 -284.847538)
		(width 0.2032)
		(layer "F.Cu")
		(net "GND")
	)
	(segment
		(start 376.966734 -220.855794)
		(end 376.966734 -220.319854)
		(width 0.2032)
		(layer "F.Cu")
		(net "GND")
	)
	(segment
		(start 281.707082 -244.066568)
		(end 282.811982 -244.066568)
		(width 0.381)
		(layer "F.Cu")
		(net "GND")
	)
	(segment
		(start 97.183448 -262.336534)
		(end 97.183448 -262.872474)
		(width 0.2032)
		(layer "F.Cu")
		(net "GND")
	)
	(segment
		(start 346.063316 -268.84757)
		(end 346.063316 -269.38351)
		(width 0.2032)
		(layer "F.Cu")
		(net "GND")
	)
	(segment
		(start 350.000316 -335.886552)
		(end 350.000316 -336.115406)
		(width 0.2032)
		(layer "F.Cu")
		(net "GND")
	)
	(segment
		(start 353.242626 -238.560102)
		(end 353.242626 -239.169448)
		(width 0.254)
		(layer "F.Cu")
		(net "GND")
	)
	(segment
		(start 196.532246 -311.216802)
		(end 195.427346 -311.216802)
		(width 0.381)
		(layer "F.Cu")
		(net "GND")
	)
	(segment
		(start 341.254334 -214.344758)
		(end 341.254334 -213.732618)
		(width 0.254)
		(layer "F.Cu")
		(net "GND")
	)
	(segment
		(start 457.221082 -271.266666)
		(end 456.116182 -271.266666)
		(width 0.381)
		(layer "F.Cu")
		(net "GND")
	)
	(segment
		(start 282.811982 -288.266632)
		(end 283.916882 -288.266632)
		(width 0.381)
		(layer "F.Cu")
		(net "GND")
	)
	(segment
		(start 184.439814 -219.41663)
		(end 185.544714 -219.41663)
		(width 0.381)
		(layer "F.Cu")
		(net "GND")
	)
	(segment
		(start 282.811982 -301.01667)
		(end 283.916882 -301.01667)
		(width 0.381)
		(layer "F.Cu")
		(net "GND")
	)
	(segment
		(start 336.085434 -245.55069)
		(end 336.085434 -246.08663)
		(width 0.2032)
		(layer "F.Cu")
		(net "GND")
	)
	(segment
		(start 164.292026 -216.866724)
		(end 162.913314 -216.866724)
		(width 0.381)
		(layer "F.Cu")
		(net "GND")
	)
	(segment
		(start 207.071214 -211.766658)
		(end 208.176114 -211.766658)
		(width 0.381)
		(layer "F.Cu")
		(net "GND")
	)
	(segment
		(start 307.782214 -279.766776)
		(end 308.887114 -279.766776)
		(width 0.381)
		(layer "F.Cu")
		(net "GND")
	)
	(segment
		(start 272.273014 -270.416782)
		(end 271.168114 -270.416782)
		(width 0.381)
		(layer "F.Cu")
		(net "GND")
	)
	(segment
		(start 39.420546 -199.01662)
		(end 38.315646 -199.01662)
		(width 0.381)
		(layer "F.Cu")
		(net "GND")
	)
	(segment
		(start 115.460272 -19.30019)
		(end 115.460272 -20.010628)
		(width 0.3556)
		(layer "F.Cu")
		(net "GND")
	)
	(segment
		(start 108.461048 -270.475456)
		(end 108.461048 -271.011142)
		(width 0.2032)
		(layer "F.Cu")
		(net "GND")
	)
	(segment
		(start 384.595116 -277.522178)
		(end 384.594862 -277.522432)
		(width 0.254)
		(layer "F.Cu")
		(net "GND")
	)
	(segment
		(start 180.339746 -238.966756)
		(end 181.444646 -238.966756)
		(width 0.381)
		(layer "F.Cu")
		(net "GND")
	)
	(segment
		(start 307.782214 -265.316716)
		(end 308.887114 -265.316716)
		(width 0.381)
		(layer "F.Cu")
		(net "GND")
	)
	(segment
		(start 371.437916 -284.033468)
		(end 371.437662 -284.033722)
		(width 0.254)
		(layer "F.Cu")
		(net "GND")
	)
	(segment
		(start 382.245362 -261.522718)
		(end 382.245362 -262.058404)
		(width 0.2032)
		(layer "F.Cu")
		(net "GND")
	)
	(segment
		(start 93.314266 -245.27256)
		(end 93.314012 -245.272306)
		(width 0.2032)
		(layer "F.Cu")
		(net "GND")
	)
	(segment
		(start 86.265766 -241.203226)
		(end 86.735666 -241.481102)
		(width 0.254)
		(layer "F.Cu")
		(net "GND")
	)
	(segment
		(start 463.659982 -241.516662)
		(end 464.764882 -241.516662)
		(width 0.381)
		(layer "F.Cu")
		(net "GND")
	)
	(segment
		(start 377.076716 -254.733298)
		(end 377.076462 -254.733552)
		(width 0.254)
		(layer "F.Cu")
		(net "GND")
	)
	(segment
		(start 375.666762 -253.383796)
		(end 375.666762 -253.919482)
		(width 0.2032)
		(layer "F.Cu")
		(net "GND")
	)
	(segment
		(start 357.70058 -223.297496)
		(end 357.70058 -222.76181)
		(width 0.254)
		(layer "F.Cu")
		(net "GND")
	)
	(segment
		(start 165.252146 -244.916706)
		(end 166.357046 -244.916706)
		(width 0.381)
		(layer "F.Cu")
		(net "GND")
	)
	(segment
		(start 23.228046 -221.96679)
		(end 24.332946 -221.96679)
		(width 0.381)
		(layer "F.Cu")
		(net "GND")
	)
	(segment
		(start 112.710976 -110.236762)
		(end 112.710976 -109.106462)
		(width 0.3556)
		(layer "F.Cu")
		(net "GND")
	)
	(segment
		(start 148.19122 -36.619688)
		(end 148.19122 -38.971728)
		(width 0.3556)
		(layer "F.Cu")
		(net "GND")
	)
	(segment
		(start 308.887114 -283.166566)
		(end 309.992014 -283.166566)
		(width 0.381)
		(layer "F.Cu")
		(net "GND")
	)
	(segment
		(start 345.554554 -55.953914)
		(end 345.15171 -55.355236)
		(width 0.2032)
		(layer "F.Cu")
		(net "GND")
	)
	(segment
		(start 332.422246 -52.679346)
		(end 332.422246 -51.739546)
		(width 0.2032)
		(layer "F.Cu")
		(net "GND")
	)
	(segment
		(start 121.038112 -223.297496)
		(end 121.038112 -222.76181)
		(width 0.254)
		(layer "F.Cu")
		(net "GND")
	)
	(segment
		(start 131.485894 -281.05608)
		(end 131.485894 -281.591512)
		(width 0.254)
		(layer "F.Cu")
		(net "GND")
	)
	(segment
		(start 137.93089 -112.01527)
		(end 138.350244 -112.434624)
		(width 0.3556)
		(layer "F.Cu")
		(net "GND")
	)
	(segment
		(start 102.75824 -334.191102)
		(end 102.464616 -334.191102)
		(width 0.2032)
		(layer "F.Cu")
		(net "GND")
	)
	(segment
		(start 326.246998 -58.49112)
		(end 326.38746 -58.152284)
		(width 0.254)
		(layer "F.Cu")
		(net "GND")
	)
	(segment
		(start 372.267734 -230.622602)
		(end 372.267734 -230.086916)
		(width 0.2032)
		(layer "F.Cu")
		(net "GND")
	)
	(segment
		(start 214.041736 -99.79152)
		(end 213.051136 -99.79152)
		(width 0.3556)
		(layer "F.Cu")
		(net "GND")
	)
	(segment
		(start 350.652334 -224.111566)
		(end 350.652334 -223.575626)
		(width 0.2032)
		(layer "F.Cu")
		(net "GND")
	)
	(segment
		(start 22.123146 -283.166566)
		(end 23.228046 -283.166566)
		(width 0.381)
		(layer "F.Cu")
		(net "GND")
	)
	(segment
		(start 285.150814 -295.06672)
		(end 286.255714 -295.06672)
		(width 0.381)
		(layer "F.Cu")
		(net "GND")
	)
	(segment
		(start 120.678448 -273.730974)
		(end 120.678194 -274.266914)
		(width 0.2032)
		(layer "F.Cu")
		(net "GND")
	)
	(segment
		(start 276.373082 -269.566644)
		(end 275.268182 -269.566644)
		(width 0.381)
		(layer "F.Cu")
		(net "GND")
	)
	(segment
		(start 266.619482 -301.01667)
		(end 267.724382 -301.01667)
		(width 0.381)
		(layer "F.Cu")
		(net "GND")
	)
	(segment
		(start 158.813246 -289.11677)
		(end 159.918146 -289.11677)
		(width 0.381)
		(layer "F.Cu")
		(net "GND")
	)
	(segment
		(start 99.422966 -236.319568)
		(end 99.422966 -235.783882)
		(width 0.2032)
		(layer "F.Cu")
		(net "GND")
	)
	(segment
		(start 185.544714 -198.166736)
		(end 186.649614 -198.166736)
		(width 0.381)
		(layer "F.Cu")
		(net "GND")
	)
	(segment
		(start 332.733904 -269.94866)
		(end 332.752446 -269.938754)
		(width 0.2032)
		(layer "F.Cu")
		(net "GND")
	)
	(segment
		(start 357.230934 -238.761524)
		(end 357.23068 -238.76127)
		(width 0.254)
		(layer "F.Cu")
		(net "GND")
	)
	(segment
		(start 26.223214 -233.86669)
		(end 27.328114 -233.86669)
		(width 0.381)
		(layer "F.Cu")
		(net "GND")
	)
	(segment
		(start 418.397182 -205.816708)
		(end 417.292282 -205.816708)
		(width 0.381)
		(layer "F.Cu")
		(net "GND")
	)
	(segment
		(start 115.869466 -233.87812)
		(end 115.869212 -233.877866)
		(width 0.2032)
		(layer "F.Cu")
		(net "GND")
	)
	(segment
		(start 341.918798 -49.390046)
		(end 341.37727 -50.329846)
		(width 0.2032)
		(layer "F.Cu")
		(net "GND")
	)
	(segment
		(start 170.457114 -295.916604)
		(end 171.562014 -295.916604)
		(width 0.381)
		(layer "F.Cu")
		(net "GND")
	)
	(segment
		(start 161.808414 -316.316614)
		(end 162.913314 -316.316614)
		(width 0.381)
		(layer "F.Cu")
		(net "GND")
	)
	(segment
		(start 441.028582 -305.266598)
		(end 442.133482 -305.266598)
		(width 0.381)
		(layer "F.Cu")
		(net "GND")
	)
	(segment
		(start 131.956048 -287.288986)
		(end 131.955794 -287.28924)
		(width 0.254)
		(layer "F.Cu")
		(net "GND")
	)
	(segment
		(start 158.813246 -236.416596)
		(end 159.718248 -236.416596)
		(width 0.381)
		(layer "F.Cu")
		(net "GND")
	)
	(segment
		(start 448.572382 -221.116652)
		(end 447.467482 -221.116652)
		(width 0.381)
		(layer "F.Cu")
		(net "GND")
	)
	(segment
		(start 348.882716 -260.708902)
		(end 348.882716 -261.244588)
		(width 0.254)
		(layer "F.Cu")
		(net "GND")
	)
	(segment
		(start 344.07348 -233.877866)
		(end 344.07348 -233.34218)
		(width 0.2032)
		(layer "F.Cu")
		(net "GND")
	)
	(segment
		(start 424.836082 -215.166702)
		(end 425.940982 -215.166702)
		(width 0.381)
		(layer "F.Cu")
		(net "GND")
	)
	(segment
		(start 193.088514 -266.1666)
		(end 191.983614 -266.1666)
		(width 0.381)
		(layer "F.Cu")
		(net "GND")
	)
	(segment
		(start 276.373082 -196.466714)
		(end 275.268182 -196.466714)
		(width 0.381)
		(layer "F.Cu")
		(net "GND")
	)
	(segment
		(start 105.061512 -216.250774)
		(end 105.061766 -216.25052)
		(width 0.254)
		(layer "F.Cu")
		(net "GND")
	)
	(segment
		(start 425.940982 -284.866588)
		(end 424.836082 -284.866588)
		(width 0.381)
		(layer "F.Cu")
		(net "GND")
	)
	(segment
		(start 441.028582 -233.86669)
		(end 442.133482 -233.86669)
		(width 0.381)
		(layer "F.Cu")
		(net "GND")
	)
	(segment
		(start 77.746098 -145.206212)
		(end 77.497178 -145.455132)
		(width 0.3556)
		(layer "F.Cu")
		(net "GND")
	)
	(segment
		(start 20.889214 -308.666642)
		(end 19.784314 -308.666642)
		(width 0.381)
		(layer "F.Cu")
		(net "GND")
	)
	(segment
		(start 433.484782 -261.066788)
		(end 434.589682 -261.066788)
		(width 0.381)
		(layer "F.Cu")
		(net "GND")
	)
	(segment
		(start 362.509562 -277.800562)
		(end 362.509562 -278.336248)
		(width 0.254)
		(layer "F.Cu")
		(net "GND")
	)
	(segment
		(start 166.17315 -421.035226)
		(end 166.80815 -421.035226)
		(width 0.3556)
		(layer "F.Cu")
		(net "GND")
	)
	(segment
		(start 352.062034 -229.808532)
		(end 352.062034 -229.272846)
		(width 0.2032)
		(layer "F.Cu")
		(net "GND")
	)
	(segment
		(start 418.397182 -221.116652)
		(end 417.292282 -221.116652)
		(width 0.381)
		(layer "F.Cu")
		(net "GND")
	)
	(segment
		(start 358.280716 -261.244588)
		(end 358.280462 -261.244842)
		(width 0.254)
		(layer "F.Cu")
		(net "GND")
	)
	(segment
		(start 297.899582 -294.216582)
		(end 299.004482 -294.216582)
		(width 0.381)
		(layer "F.Cu")
		(net "GND")
	)
	(segment
		(start 214.615014 -277.216616)
		(end 215.719914 -277.216616)
		(width 0.381)
		(layer "F.Cu")
		(net "GND")
	)
	(segment
		(start 256.080514 -236.416596)
		(end 257.185414 -236.416596)
		(width 0.381)
		(layer "F.Cu")
		(net "GND")
	)
	(segment
		(start 195.427346 -244.916706)
		(end 196.532246 -244.916706)
		(width 0.381)
		(layer "F.Cu")
		(net "GND")
	)
	(segment
		(start 30.248098 -138.39698)
		(end 30.248098 -139.066524)
		(width 0.3556)
		(layer "F.Cu")
		(net "GND")
	)
	(segment
		(start 427.230032 -397.09852)
		(end 426.595032 -397.09852)
		(width 0.3556)
		(layer "F.Cu")
		(net "GND")
	)
	(segment
		(start 348.302834 -237.947454)
		(end 348.302834 -237.411514)
		(width 0.254)
		(layer "F.Cu")
		(net "GND")
	)
	(segment
		(start 54.508146 -204.96657)
		(end 53.403246 -204.96657)
		(width 0.381)
		(layer "F.Cu")
		(net "GND")
	)
	(segment
		(start 188.839348 -423.209212)
		(end 189.1792 -422.86936)
		(width 0.3556)
		(layer "F.Cu")
		(net "GND")
	)
	(segment
		(start 362.039916 -272.103342)
		(end 362.039662 -272.639282)
		(width 0.2032)
		(layer "F.Cu")
		(net "GND")
	)
	(segment
		(start 293.799514 -234.716574)
		(end 292.694614 -234.716574)
		(width 0.381)
		(layer "F.Cu")
		(net "GND")
	)
	(segment
		(start 232.000044 -55.16499)
		(end 230.984044 -55.16499)
		(width 0.381)
		(layer "F.Cu")
		(net "GND")
	)
	(segment
		(start 88.145366 -214.622888)
		(end 88.145112 -214.622634)
		(width 0.1778)
		(layer "F.Cu")
		(net "GND")
	)
	(segment
		(start 111.170212 -232.250234)
		(end 111.170212 -231.714548)
		(width 0.254)
		(layer "F.Cu")
		(net "GND")
	)
	(segment
		(start 87.785194 -270.475456)
		(end 87.785194 -271.011396)
		(width 0.254)
		(layer "F.Cu")
		(net "GND")
	)
	(segment
		(start 278.0792 -420.31158)
		(end 275.66874 -420.31158)
		(width 0.3556)
		(layer "F.Cu")
		(net "GND")
	)
	(segment
		(start 160.112202 -285.667196)
		(end 159.840676 -285.667196)
		(width 0.381)
		(layer "F.Cu")
		(net "GND")
	)
	(segment
		(start 32.445452 -167.443404)
		(end 32.591502 -167.297354)
		(width 0.381)
		(layer "F.Cu")
		(net "GND")
	)
	(segment
		(start 94.723712 -220.041978)
		(end 94.723966 -220.041724)
		(width 0.254)
		(layer "F.Cu")
		(net "GND")
	)
	(segment
		(start 89.555066 -217.600276)
		(end 89.555066 -217.064336)
		(width 0.2032)
		(layer "F.Cu")
		(net "GND")
	)
	(segment
		(start 445.577214 -197.316598)
		(end 444.472314 -197.316598)
		(width 0.381)
		(layer "F.Cu")
		(net "GND")
	)
	(segment
		(start 263.624314 -292.516814)
		(end 264.729214 -292.516814)
		(width 0.381)
		(layer "F.Cu")
		(net "GND")
	)
	(segment
		(start 266.619482 -241.516662)
		(end 267.724382 -241.516662)
		(width 0.381)
		(layer "F.Cu")
		(net "GND")
	)
	(segment
		(start 121.977912 -226.553268)
		(end 121.977912 -226.017582)
		(width 0.254)
		(layer "F.Cu")
		(net "GND")
	)
	(segment
		(start 429.384714 -296.766742)
		(end 430.489614 -296.766742)
		(width 0.381)
		(layer "F.Cu")
		(net "GND")
	)
	(segment
		(start 375.087134 -220.855794)
		(end 375.087134 -220.319854)
		(width 0.2032)
		(layer "F.Cu")
		(net "GND")
	)
	(segment
		(start 169.352214 -308.666642)
		(end 170.457114 -308.666642)
		(width 0.381)
		(layer "F.Cu")
		(net "GND")
	)
	(segment
		(start 429.384714 -233.016806)
		(end 430.489614 -233.016806)
		(width 0.381)
		(layer "F.Cu")
		(net "GND")
	)
	(segment
		(start 116.919248 -264.499852)
		(end 116.918994 -264.500106)
		(width 0.2032)
		(layer "F.Cu")
		(net "GND")
	)
	(segment
		(start 190.01359 -67.391788)
		(end 189.40399 -67.391788)
		(width 0.3556)
		(layer "F.Cu")
		(net "GND")
	)
	(segment
		(start 128.666494 -285.939484)
		(end 128.666494 -286.475424)
		(width 0.2032)
		(layer "F.Cu")
		(net "GND")
	)
	(segment
		(start 23.228046 -225.36658)
		(end 24.332946 -225.36658)
		(width 0.381)
		(layer "F.Cu")
		(net "GND")
	)
	(segment
		(start 120.678448 -281.869896)
		(end 120.678448 -282.405582)
		(width 0.254)
		(layer "F.Cu")
		(net "GND")
	)
	(segment
		(start 335.615534 -222.48368)
		(end 335.615534 -221.94774)
		(width 0.254)
		(layer "F.Cu")
		(net "GND")
	)
	(segment
		(start 464.764882 -284.866588)
		(end 463.659982 -284.866588)
		(width 0.381)
		(layer "F.Cu")
		(net "GND")
	)
	(segment
		(start 216.943178 -23.172928)
		(end 217.062558 -23.292308)
		(width 0.3556)
		(layer "F.Cu")
		(net "GND")
	)
	(segment
		(start 30.771846 -261.916672)
		(end 31.876746 -261.916672)
		(width 0.381)
		(layer "F.Cu")
		(net "GND")
	)
	(segment
		(start 366.297464 -333.763112)
		(end 366.297464 -333.330804)
		(width 0.2032)
		(layer "F.Cu")
		(net "GND")
	)
	(segment
		(start 353.581716 -276.986492)
		(end 353.581716 -277.521924)
		(width 0.2032)
		(layer "F.Cu")
		(net "GND")
	)
	(segment
		(start 115.979448 -266.127992)
		(end 115.979194 -266.128246)
		(width 0.254)
		(layer "F.Cu")
		(net "GND")
	)
	(segment
		(start 346.423234 -228.180646)
		(end 346.423234 -227.64496)
		(width 0.2032)
		(layer "F.Cu")
		(net "GND")
	)
	(segment
		(start 100.472494 -264.778236)
		(end 100.472494 -265.313922)
		(width 0.254)
		(layer "F.Cu")
		(net "GND")
	)
	(segment
		(start 204.076046 -223.666558)
		(end 205.180946 -223.666558)
		(width 0.381)
		(layer "F.Cu")
		(net "GND")
	)
	(segment
		(start 281.707082 -275.516594)
		(end 282.811982 -275.516594)
		(width 0.381)
		(layer "F.Cu")
		(net "GND")
	)
	(segment
		(start 369.91798 -222.76181)
		(end 369.918234 -222.761556)
		(width 0.254)
		(layer "F.Cu")
		(net "GND")
	)
	(segment
		(start 297.899582 -216.866724)
		(end 299.004482 -216.866724)
		(width 0.381)
		(layer "F.Cu")
		(net "GND")
	)
	(segment
		(start 453.121014 -244.916706)
		(end 452.016114 -244.916706)
		(width 0.381)
		(layer "F.Cu")
		(net "GND")
	)
	(segment
		(start 100.832666 -224.111566)
		(end 100.832666 -223.575626)
		(width 0.2032)
		(layer "F.Cu")
		(net "GND")
	)
	(segment
		(start 56.398414 -289.966654)
		(end 57.503314 -289.966654)
		(width 0.381)
		(layer "F.Cu")
		(net "GND")
	)
	(segment
		(start 254.975614 -214.316564)
		(end 256.080514 -214.316564)
		(width 0.381)
		(layer "F.Cu")
		(net "GND")
	)
	(segment
		(start 57.503314 -194.766692)
		(end 58.608214 -194.766692)
		(width 0.381)
		(layer "F.Cu")
		(net "GND")
	)
	(segment
		(start 277.607014 -231.316784)
		(end 278.711914 -231.316784)
		(width 0.381)
		(layer "F.Cu")
		(net "GND")
	)
	(segment
		(start 104.231694 -271.289272)
		(end 104.231948 -271.289526)
		(width 0.2032)
		(layer "F.Cu")
		(net "GND")
	)
	(segment
		(start 101.302312 -231.436418)
		(end 101.302566 -231.436164)
		(width 0.2032)
		(layer "F.Cu")
		(net "GND")
	)
	(segment
		(start 35.976814 -305.266598)
		(end 34.871914 -305.266598)
		(width 0.381)
		(layer "F.Cu")
		(net "GND")
	)
	(segment
		(start 14.579346 -217.716608)
		(end 15.684246 -217.716608)
		(width 0.381)
		(layer "F.Cu")
		(net "GND")
	)
	(segment
		(start 335.790794 -58.889392)
		(end 335.899252 -59.265312)
		(width 0.2032)
		(layer "F.Cu")
		(net "GND")
	)
	(segment
		(start 337.495134 -238.761524)
		(end 337.49488 -238.76127)
		(width 0.254)
		(layer "F.Cu")
		(net "GND")
	)
	(segment
		(start 93.424248 -287.288986)
		(end 93.423994 -287.28924)
		(width 0.254)
		(layer "F.Cu")
		(net "GND")
	)
	(segment
		(start 438.520586 -46.736762)
		(end 438.520586 -46.033436)
		(width 0.3556)
		(layer "F.Cu")
		(net "GND")
	)
	(segment
		(start 370.027962 -277.800562)
		(end 370.027962 -278.336502)
		(width 0.254)
		(layer "F.Cu")
		(net "GND")
	)
	(segment
		(start 409.748482 -230.466646)
		(end 410.853382 -230.466646)
		(width 0.381)
		(layer "F.Cu")
		(net "GND")
	)
	(segment
		(start 120.678448 -286.7533)
		(end 120.678448 -287.288986)
		(width 0.254)
		(layer "F.Cu")
		(net "GND")
	)
	(segment
		(start 286.255714 -208.366614)
		(end 287.360614 -208.366614)
		(width 0.381)
		(layer "F.Cu")
		(net "GND")
	)
	(segment
		(start 8.140446 -212.616796)
		(end 9.245346 -212.616796)
		(width 0.381)
		(layer "F.Cu")
		(net "GND")
	)
	(segment
		(start 379.896116 -272.103342)
		(end 379.896116 -272.639282)
		(width 0.2032)
		(layer "F.Cu")
		(net "GND")
	)
	(segment
		(start 307.782214 -216.016586)
		(end 308.887114 -216.016586)
		(width 0.381)
		(layer "F.Cu")
		(net "GND")
	)
	(segment
		(start 307.782214 -227.066602)
		(end 308.887114 -227.066602)
		(width 0.381)
		(layer "F.Cu")
		(net "GND")
	)
	(segment
		(start 414.297114 -279.766776)
		(end 415.402014 -279.766776)
		(width 0.381)
		(layer "F.Cu")
		(net "GND")
	)
	(segment
		(start 372.377716 -281.869896)
		(end 372.377462 -282.405836)
		(width 0.254)
		(layer "F.Cu")
		(net "GND")
	)
	(segment
		(start 359.110534 -230.622602)
		(end 359.110534 -230.086662)
		(width 0.2032)
		(layer "F.Cu")
		(net "GND")
	)
	(segment
		(start 38.315646 -273.816572)
		(end 37.210746 -273.816572)
		(width 0.381)
		(layer "F.Cu")
		(net "GND")
	)
	(segment
		(start 261.285482 -266.1666)
		(end 260.180582 -266.1666)
		(width 0.381)
		(layer "F.Cu")
		(net "GND")
	)
	(segment
		(start 196.532246 -260.21665)
		(end 197.637146 -260.21665)
		(width 0.381)
		(layer "F.Cu")
		(net "GND")
	)
	(segment
		(start 162.913314 -278.916638)
		(end 164.018214 -278.916638)
		(width 0.381)
		(layer "F.Cu")
		(net "GND")
	)
	(segment
		(start 336.20964 -342.270334)
		(end 335.88579 -342.270334)
		(width 0.381)
		(layer "F.Cu")
		(net "GND")
	)
	(segment
		(start 377.90628 -245.272306)
		(end 377.90628 -244.73662)
		(width 0.2032)
		(layer "F.Cu")
		(net "GND")
	)
	(segment
		(start 12.240514 -224.516696)
		(end 13.345414 -224.516696)
		(width 0.381)
		(layer "F.Cu")
		(net "GND")
	)
	(segment
		(start 296.794682 -261.066788)
		(end 297.899582 -261.066788)
		(width 0.381)
		(layer "F.Cu")
		(net "GND")
	)
	(segment
		(start 281.707082 -266.1666)
		(end 282.811982 -266.1666)
		(width 0.381)
		(layer "F.Cu")
		(net "GND")
	)
	(segment
		(start 124.437648 -279.150064)
		(end 124.437394 -279.150318)
		(width 0.254)
		(layer "F.Cu")
		(net "GND")
	)
	(segment
		(start 275.268182 -267.866622)
		(end 274.163282 -267.866622)
		(width 0.381)
		(layer "F.Cu")
		(net "GND")
	)
	(segment
		(start 63.942214 -314.616592)
		(end 65.047114 -314.616592)
		(width 0.381)
		(layer "F.Cu")
		(net "GND")
	)
	(segment
		(start 435.823614 -206.666592)
		(end 436.928514 -206.666592)
		(width 0.381)
		(layer "F.Cu")
		(net "GND")
	)
	(segment
		(start 427.766988 -11.26998)
		(end 427.766988 -12.37488)
		(width 0.3556)
		(layer "F.Cu")
		(net "GND")
	)
	(segment
		(start 345.95308 -246.900192)
		(end 345.95308 -246.364506)
		(width 0.2032)
		(layer "F.Cu")
		(net "GND")
	)
	(segment
		(start 342.773762 -258.2672)
		(end 342.773762 -258.80314)
		(width 0.2032)
		(layer "F.Cu")
		(net "GND")
	)
	(segment
		(start 364.92688 -393.240768)
		(end 365.479584 -392.688064)
		(width 0.3556)
		(layer "F.Cu")
		(net "GND")
	)
	(segment
		(start 193.088514 -244.066568)
		(end 191.983614 -244.066568)
		(width 0.381)
		(layer "F.Cu")
		(net "GND")
	)
	(segment
		(start 190.093346 -234.716574)
		(end 188.988446 -234.716574)
		(width 0.381)
		(layer "F.Cu")
		(net "GND")
	)
	(segment
		(start 132.315966 -229.808532)
		(end 132.315966 -229.272846)
		(width 0.2032)
		(layer "F.Cu")
		(net "GND")
	)
	(segment
		(start 341.918798 -41.871646)
		(end 342.190578 -42.341546)
		(width 0.254)
		(layer "F.Cu")
		(net "GND")
	)
	(segment
		(start 97.543112 -220.041978)
		(end 97.543366 -220.041724)
		(width 0.254)
		(layer "F.Cu")
		(net "GND")
	)
	(segment
		(start 373.602758 -95.121984)
		(end 373.622316 -95.141542)
		(width 0.3556)
		(layer "F.Cu")
		(net "GND")
	)
	(segment
		(start 340.894162 -263.150604)
		(end 340.894162 -263.68629)
		(width 0.2032)
		(layer "F.Cu")
		(net "GND")
	)
	(segment
		(start 378.956316 -284.033468)
		(end 378.956062 -284.033722)
		(width 0.254)
		(layer "F.Cu")
		(net "GND")
	)
	(segment
		(start 341.724234 -228.180646)
		(end 341.724234 -227.64496)
		(width 0.2032)
		(layer "F.Cu")
		(net "GND")
	)
	(segment
		(start 422.945814 -306.116736)
		(end 421.840914 -306.116736)
		(width 0.381)
		(layer "F.Cu")
		(net "GND")
	)
	(segment
		(start 43.520614 -245.76659)
		(end 42.415714 -245.76659)
		(width 0.381)
		(layer "F.Cu")
		(net "GND")
	)
	(segment
		(start 191.983614 -278.916638)
		(end 193.088514 -278.916638)
		(width 0.381)
		(layer "F.Cu")
		(net "GND")
	)
	(segment
		(start 207.071214 -272.966688)
		(end 208.176114 -272.966688)
		(width 0.381)
		(layer "F.Cu")
		(net "GND")
	)
	(segment
		(start 68.76923 -52.720748)
		(end 68.76923 -53.548788)
		(width 0.3556)
		(layer "F.Cu")
		(net "GND")
	)
	(segment
		(start 439.923682 -303.566576)
		(end 441.028582 -303.566576)
		(width 0.381)
		(layer "F.Cu")
		(net "GND")
	)
	(segment
		(start 337.134962 -282.683966)
		(end 337.134962 -283.219906)
		(width 0.2032)
		(layer "F.Cu")
		(net "GND")
	)
	(segment
		(start 49.959514 -233.86669)
		(end 51.064414 -233.86669)
		(width 0.381)
		(layer "F.Cu")
		(net "GND")
	)
	(segment
		(start 86.375494 -263.150604)
		(end 87.315294 -263.686544)
		(width 0.254)
		(layer "F.Cu")
		(net "GND")
	)
	(segment
		(start 384.485134 -245.27256)
		(end 384.015234 -245.55069)
		(width 0.254)
		(layer "F.Cu")
		(net "GND")
	)
	(segment
		(start 261.285482 -232.166668)
		(end 260.180582 -232.166668)
		(width 0.381)
		(layer "F.Cu")
		(net "GND")
	)
	(segment
		(start 308.887114 -260.21665)
		(end 309.992014 -260.21665)
		(width 0.381)
		(layer "F.Cu")
		(net "GND")
	)
	(segment
		(start 407.858214 -246.616728)
		(end 406.753314 -246.616728)
		(width 0.381)
		(layer "F.Cu")
		(net "GND")
	)
	(segment
		(start 414.297114 -216.016586)
		(end 415.402014 -216.016586)
		(width 0.381)
		(layer "F.Cu")
		(net "GND")
	)
	(segment
		(start 441.028582 -258.516628)
		(end 442.133482 -258.516628)
		(width 0.381)
		(layer "F.Cu")
		(net "GND")
	)
	(segment
		(start 161.808414 -286.69361)
		(end 161.808414 -286.74441)
		(width 0.381)
		(layer "F.Cu")
		(net "GND")
	)
	(segment
		(start 374.726962 -259.894832)
		(end 374.726962 -260.430772)
		(width 0.2032)
		(layer "F.Cu")
		(net "GND")
	)
	(segment
		(start 256.080514 -267.016738)
		(end 257.185414 -267.016738)
		(width 0.381)
		(layer "F.Cu")
		(net "GND")
	)
	(segment
		(start 285.150814 -285.716726)
		(end 286.255714 -285.716726)
		(width 0.381)
		(layer "F.Cu")
		(net "GND")
	)
	(segment
		(start 106.941366 -229.808532)
		(end 106.941366 -229.272846)
		(width 0.2032)
		(layer "F.Cu")
		(net "GND")
	)
	(segment
		(start 290.355782 -264.466578)
		(end 291.460682 -264.466578)
		(width 0.381)
		(layer "F.Cu")
		(net "GND")
	)
	(segment
		(start 458.487526 -92.515182)
		(end 458.487526 -92.977462)
		(width 0.3556)
		(layer "F.Cu")
		(net "GND")
	)
	(segment
		(start 385.064762 -274.54479)
		(end 384.125216 -275.080984)
		(width 0.254)
		(layer "F.Cu")
		(net "GND")
	)
	(segment
		(start 372.26748 -233.877866)
		(end 372.26748 -233.34218)
		(width 0.254)
		(layer "F.Cu")
		(net "GND")
	)
	(segment
		(start 42.415714 -266.1666)
		(end 41.310814 -266.1666)
		(width 0.381)
		(layer "F.Cu")
		(net "GND")
	)
	(segment
		(start 33.767014 -249.166634)
		(end 34.871914 -249.166634)
		(width 0.381)
		(layer "F.Cu")
		(net "GND")
	)
	(segment
		(start 100.942394 -265.592306)
		(end 100.942648 -265.592306)
		(width 0.254)
		(layer "F.Cu")
		(net "GND")
	)
	(segment
		(start 8.140446 -236.416596)
		(end 9.245346 -236.416596)
		(width 0.381)
		(layer "F.Cu")
		(net "GND")
	)
	(segment
		(start 261.285482 -228.766624)
		(end 260.180582 -228.766624)
		(width 0.381)
		(layer "F.Cu")
		(net "GND")
	)
	(segment
		(start 361.45978 -236.319822)
		(end 361.460034 -236.319568)
		(width 0.2032)
		(layer "F.Cu")
		(net "GND")
	)
	(segment
		(start 405.648414 -231.316784)
		(end 406.753314 -231.316784)
		(width 0.381)
		(layer "F.Cu")
		(net "GND")
	)
	(segment
		(start 335.67878 -54.558946)
		(end 336.49285 -54.089046)
		(width 0.2032)
		(layer "F.Cu")
		(net "GND")
	)
	(segment
		(start 368.97818 -222.76181)
		(end 368.978434 -222.761556)
		(width 0.254)
		(layer "F.Cu")
		(net "GND")
	)
	(segment
		(start 418.397182 -258.516628)
		(end 417.292282 -258.516628)
		(width 0.381)
		(layer "F.Cu")
		(net "GND")
	)
	(segment
		(start 89.084912 -215.158574)
		(end 89.084912 -214.622888)
		(width 0.2032)
		(layer "F.Cu")
		(net "GND")
	)
	(segment
		(start 263.624314 -285.716726)
		(end 264.729214 -285.716726)
		(width 0.381)
		(layer "F.Cu")
		(net "GND")
	)
	(segment
		(start 326.193658 -37.983668)
		(end 326.263 -37.982144)
		(width 0.2032)
		(layer "F.Cu")
		(net "GND")
	)
	(segment
		(start 99.422712 -222.76181)
		(end 99.422966 -222.761556)
		(width 0.254)
		(layer "F.Cu")
		(net "GND")
	)
	(segment
		(start 134.314184 -345.793314)
		(end 134.225538 -345.793314)
		(width 0.254)
		(layer "F.Cu")
		(net "GND")
	)
	(segment
		(start 292.694614 -233.016806)
		(end 293.799514 -233.016806)
		(width 0.381)
		(layer "F.Cu")
		(net "GND")
	)
	(segment
		(start 63.726314 -310.366664)
		(end 65.047114 -310.366664)
		(width 0.381)
		(layer "F.Cu")
		(net "GND")
	)
	(segment
		(start 91.434666 -214.344758)
		(end 91.434666 -213.732618)
		(width 0.254)
		(layer "F.Cu")
		(net "GND")
	)
	(segment
		(start 11.135614 -194.766692)
		(end 12.240514 -194.766692)
		(width 0.381)
		(layer "F.Cu")
		(net "GND")
	)
	(segment
		(start 445.361822 -12.37361)
		(end 445.361822 -11.26998)
		(width 0.3556)
		(layer "F.Cu")
		(net "GND")
	)
	(segment
		(start 7.035546 -204.96657)
		(end 8.140446 -204.96657)
		(width 0.381)
		(layer "F.Cu")
		(net "GND")
	)
	(segment
		(start 311.882282 -275.516594)
		(end 312.987182 -275.516594)
		(width 0.381)
		(layer "F.Cu")
		(net "GND")
	)
	(segment
		(start 49.666906 -9.424924)
		(end 49.666906 -8.320024)
		(width 0.3556)
		(layer "F.Cu")
		(net "GND")
	)
	(segment
		(start 306.83454 -430.26965)
		(end 306.83454 -429.632618)
		(width 0.3556)
		(layer "F.Cu")
		(net "GND")
	)
	(segment
		(start 449.677282 -280.61666)
		(end 448.572382 -280.61666)
		(width 0.381)
		(layer "F.Cu")
		(net "GND")
	)
	(segment
		(start 157.708346 -242.3668)
		(end 158.813246 -242.3668)
		(width 0.381)
		(layer "F.Cu")
		(net "GND")
	)
	(segment
		(start 92.014294 -269.66164)
		(end 92.014294 -270.19758)
		(width 0.2032)
		(layer "F.Cu")
		(net "GND")
	)
	(segment
		(start 345.722194 -60.057792)
		(end 345.37523 -59.914028)
		(width 0.2032)
		(layer "F.Cu")
		(net "GND")
	)
	(segment
		(start 372.73738 -216.250774)
		(end 372.737634 -216.25052)
		(width 0.254)
		(layer "F.Cu")
		(net "GND")
	)
	(segment
		(start 294.904414 -225.36658)
		(end 293.799514 -225.36658)
		(width 0.381)
		(layer "F.Cu")
		(net "GND")
	)
	(segment
		(start 312.987182 -244.066568)
		(end 314.092082 -244.066568)
		(width 0.381)
		(layer "F.Cu")
		(net "GND")
	)
	(segment
		(start 202.971146 -279.766776)
		(end 204.076046 -279.766776)
		(width 0.381)
		(layer "F.Cu")
		(net "GND")
	)
	(segment
		(start 433.484782 -280.61666)
		(end 434.589682 -280.61666)
		(width 0.381)
		(layer "F.Cu")
		(net "GND")
	)
	(segment
		(start 118.485666 -335.855056)
		(end 118.312438 -336.27314)
		(width 0.1778)
		(layer "F.Cu")
		(net "GND")
	)
	(segment
		(start 48.854614 -301.01667)
		(end 49.959514 -301.01667)
		(width 0.381)
		(layer "F.Cu")
		(net "GND")
	)
	(segment
		(start 133.365494 -259.894832)
		(end 133.365494 -260.430772)
		(width 0.2032)
		(layer "F.Cu")
		(net "GND")
	)
	(segment
		(start 276.373082 -262.76681)
		(end 275.268182 -262.76681)
		(width 0.381)
		(layer "F.Cu")
		(net "GND")
	)
	(segment
		(start 162.913314 -226.216718)
		(end 161.808414 -226.216718)
		(width 0.381)
		(layer "F.Cu")
		(net "GND")
	)
	(segment
		(start 171.562014 -269.566644)
		(end 170.457114 -269.566644)
		(width 0.381)
		(layer "F.Cu")
		(net "GND")
	)
	(segment
		(start 136.655048 -257.45313)
		(end 136.655048 -257.98907)
		(width 0.254)
		(layer "F.Cu")
		(net "GND")
	)
	(segment
		(start 278.711914 -225.36658)
		(end 279.816814 -225.36658)
		(width 0.381)
		(layer "F.Cu")
		(net "GND")
	)
	(segment
		(start 271.168114 -229.616762)
		(end 270.063214 -229.616762)
		(width 0.381)
		(layer "F.Cu")
		(net "GND")
	)
	(segment
		(start 346.42298 -233.064304)
		(end 346.42298 -232.528364)
		(width 0.2032)
		(layer "F.Cu")
		(net "GND")
	)
	(segment
		(start 130.906266 -250.155964)
		(end 130.906012 -250.15571)
		(width 0.2032)
		(layer "F.Cu")
		(net "GND")
	)
	(segment
		(start 30.771846 -258.516628)
		(end 31.876746 -258.516628)
		(width 0.381)
		(layer "F.Cu")
		(net "GND")
	)
	(segment
		(start 202.971146 -212.616796)
		(end 204.076046 -212.616796)
		(width 0.381)
		(layer "F.Cu")
		(net "GND")
	)
	(segment
		(start 161.808414 -305.266598)
		(end 162.913314 -305.266598)
		(width 0.381)
		(layer "F.Cu")
		(net "GND")
	)
	(segment
		(start 349.712026 -59.543188)
		(end 348.56039 -59.543188)
		(width 0.2032)
		(layer "F.Cu")
		(net "GND")
	)
	(segment
		(start 433.484782 -245.76659)
		(end 434.589682 -245.76659)
		(width 0.381)
		(layer "F.Cu")
		(net "GND")
	)
	(segment
		(start 285.150814 -307.816758)
		(end 286.255714 -307.816758)
		(width 0.381)
		(layer "F.Cu")
		(net "GND")
	)
	(segment
		(start 113.519712 -244.458744)
		(end 113.519712 -243.923566)
		(width 0.254)
		(layer "F.Cu")
		(net "GND")
	)
	(segment
		(start 425.940982 -316.316614)
		(end 424.836082 -316.316614)
		(width 0.381)
		(layer "F.Cu")
		(net "GND")
	)
	(segment
		(start 30.771846 -296.766742)
		(end 31.876746 -296.766742)
		(width 0.381)
		(layer "F.Cu")
		(net "GND")
	)
	(segment
		(start 122.558048 -278.614378)
		(end 122.558048 -279.150064)
		(width 0.254)
		(layer "F.Cu")
		(net "GND")
	)
	(segment
		(start 163.10483 -435.447948)
		(end 162.49523 -435.447948)
		(width 0.3556)
		(layer "F.Cu")
		(net "GND")
	)
	(segment
		(start 30.771846 -313.766708)
		(end 31.876746 -313.766708)
		(width 0.381)
		(layer "F.Cu")
		(net "GND")
	)
	(segment
		(start 184.439814 -244.066568)
		(end 185.544714 -244.066568)
		(width 0.381)
		(layer "F.Cu")
		(net "GND")
	)
	(segment
		(start 175.005746 -206.666592)
		(end 173.900846 -206.666592)
		(width 0.381)
		(layer "F.Cu")
		(net "GND")
	)
	(segment
		(start 383.655062 -273.730974)
		(end 383.655062 -274.266914)
		(width 0.254)
		(layer "F.Cu")
		(net "GND")
	)
	(segment
		(start 197.637146 -285.716726)
		(end 196.532246 -285.716726)
		(width 0.381)
		(layer "F.Cu")
		(net "GND")
	)
	(segment
		(start 190.093346 -212.616796)
		(end 188.988446 -212.616796)
		(width 0.381)
		(layer "F.Cu")
		(net "GND")
	)
	(segment
		(start 346.799662 -39.445946)
		(end 346.799662 -39.360602)
		(width 0.2032)
		(layer "F.Cu")
		(net "GND")
	)
	(segment
		(start 352.06178 -222.76181)
		(end 352.062034 -222.761556)
		(width 0.254)
		(layer "F.Cu")
		(net "GND")
	)
	(segment
		(start 162.913314 -258.516628)
		(end 164.018214 -258.516628)
		(width 0.381)
		(layer "F.Cu")
		(net "GND")
	)
	(segment
		(start 25.39492 -430.797208)
		(end 25.47366 -430.875948)
		(width 0.3556)
		(layer "F.Cu")
		(net "GND")
	)
	(segment
		(start 42.415714 -216.866724)
		(end 41.310814 -216.866724)
		(width 0.381)
		(layer "F.Cu")
		(net "GND")
	)
	(segment
		(start 89.084912 -223.297496)
		(end 89.084912 -222.76181)
		(width 0.254)
		(layer "F.Cu")
		(net "GND")
	)
	(segment
		(start 346.653358 -53.063648)
		(end 346.384626 -52.952396)
		(width 0.2032)
		(layer "F.Cu")
		(net "GND")
	)
	(segment
		(start 56.398414 -202.416664)
		(end 57.503314 -202.416664)
		(width 0.381)
		(layer "F.Cu")
		(net "GND")
	)
	(segment
		(start 110.700566 -220.041978)
		(end 110.700566 -219.506038)
		(width 0.254)
		(layer "F.Cu")
		(net "GND")
	)
	(segment
		(start 439.923682 -204.116686)
		(end 441.028582 -204.116686)
		(width 0.381)
		(layer "F.Cu")
		(net "GND")
	)
	(segment
		(start 112.710976 -116.078762)
		(end 112.710976 -114.925348)
		(width 0.3556)
		(layer "F.Cu")
		(net "GND")
	)
	(segment
		(start 276.373082 -204.116686)
		(end 275.268182 -204.116686)
		(width 0.381)
		(layer "F.Cu")
		(net "GND")
	)
	(segment
		(start 87.675466 -242.017042)
		(end 87.675466 -241.481102)
		(width 0.254)
		(layer "F.Cu")
		(net "GND")
	)
	(segment
		(start 386.944362 -261.522718)
		(end 387.883908 -262.058404)
		(width 0.254)
		(layer "F.Cu")
		(net "GND")
	)
	(segment
		(start 373.787162 -284.311598)
		(end 373.787416 -284.847538)
		(width 0.254)
		(layer "F.Cu")
		(net "GND")
	)
	(segment
		(start 345.48318 -220.041978)
		(end 345.483434 -220.041724)
		(width 0.254)
		(layer "F.Cu")
		(net "GND")
	)
	(segment
		(start 15.684246 -242.3668)
		(end 16.789146 -242.3668)
		(width 0.381)
		(layer "F.Cu")
		(net "GND")
	)
	(segment
		(start 137.153396 -273.475958)
		(end 137.130536 -273.453098)
		(width 0.254)
		(layer "F.Cu")
		(net "GND")
	)
	(segment
		(start 14.579346 -317.166752)
		(end 15.684246 -317.166752)
		(width 0.381)
		(layer "F.Cu")
		(net "GND")
	)
	(segment
		(start 116.449094 -286.47517)
		(end 116.449348 -286.475424)
		(width 0.254)
		(layer "F.Cu")
		(net "GND")
	)
	(segment
		(start 135.006842 -33.477708)
		(end 134.067042 -33.477708)
		(width 0.3556)
		(layer "F.Cu")
		(net "GND")
	)
	(segment
		(start 289.250882 -233.86669)
		(end 290.355782 -233.86669)
		(width 0.381)
		(layer "F.Cu")
		(net "GND")
	)
	(segment
		(start 410.853382 -288.266632)
		(end 409.419044 -288.266632)
		(width 0.381)
		(layer "F.Cu")
		(net "GND")
	)
	(segment
		(start 98.592894 -259.894832)
		(end 98.592894 -260.430772)
		(width 0.2032)
		(layer "F.Cu")
		(net "GND")
	)
	(segment
		(start 307.782214 -244.916706)
		(end 308.887114 -244.916706)
		(width 0.381)
		(layer "F.Cu")
		(net "GND")
	)
	(segment
		(start 340.784434 -228.180646)
		(end 340.784434 -227.64496)
		(width 0.2032)
		(layer "F.Cu")
		(net "GND")
	)
	(segment
		(start 462.555082 -202.416664)
		(end 463.659982 -202.416664)
		(width 0.381)
		(layer "F.Cu")
		(net "GND")
	)
	(segment
		(start 343.243916 -257.988816)
		(end 343.243662 -257.98907)
		(width 0.2032)
		(layer "F.Cu")
		(net "GND")
	)
	(segment
		(start 125.267466 -245.27256)
		(end 125.267466 -244.73662)
		(width 0.2032)
		(layer "F.Cu")
		(net "GND")
	)
	(segment
		(start 49.959514 -205.816708)
		(end 51.064414 -205.816708)
		(width 0.381)
		(layer "F.Cu")
		(net "GND")
	)
	(segment
		(start 353.00158 -223.297496)
		(end 353.00158 -222.76181)
		(width 0.254)
		(layer "F.Cu")
		(net "GND")
	)
	(segment
		(start 266.619482 -235.566712)
		(end 267.724382 -235.566712)
		(width 0.381)
		(layer "F.Cu")
		(net "GND")
	)
	(segment
		(start 345.554554 -46.949614)
		(end 345.96959 -47.44974)
		(width 0.2032)
		(layer "F.Cu")
		(net "GND")
	)
	(segment
		(start 457.221082 -289.966654)
		(end 456.116182 -289.966654)
		(width 0.381)
		(layer "F.Cu")
		(net "GND")
	)
	(segment
		(start 121.618248 -272.103342)
		(end 121.617994 -272.639282)
		(width 0.2032)
		(layer "F.Cu")
		(net "GND")
	)
	(segment
		(start 207.071214 -289.966654)
		(end 208.176114 -289.966654)
		(width 0.381)
		(layer "F.Cu")
		(net "GND")
	)
	(segment
		(start 170.457114 -305.266598)
		(end 169.352214 -305.266598)
		(width 0.381)
		(layer "F.Cu")
		(net "GND")
	)
	(segment
		(start 211.102956 -29.876242)
		(end 211.102956 -29.266642)
		(width 0.3556)
		(layer "F.Cu")
		(net "GND")
	)
	(segment
		(start 427.045882 -291.666676)
		(end 425.940982 -291.666676)
		(width 0.381)
		(layer "F.Cu")
		(net "GND")
	)
	(segment
		(start 48.155606 -355.947218)
		(end 48.155606 -355.717602)
		(width 0.2032)
		(layer "F.Cu")
		(net "GND")
	)
	(segment
		(start 172.795946 -279.766776)
		(end 173.900846 -279.766776)
		(width 0.381)
		(layer "F.Cu")
		(net "GND")
	)
	(segment
		(start 350.762062 -265.592306)
		(end 350.762062 -266.128246)
		(width 0.2032)
		(layer "F.Cu")
		(net "GND")
	)
	(segment
		(start 330.396596 -58.020204)
		(end 330.896976 -57.605168)
		(width 0.2032)
		(layer "F.Cu")
		(net "GND")
	)
	(segment
		(start 285.150814 -263.616694)
		(end 286.255714 -263.616694)
		(width 0.381)
		(layer "F.Cu")
		(net "GND")
	)
	(segment
		(start 436.928514 -206.666592)
		(end 438.033414 -206.666592)
		(width 0.381)
		(layer "F.Cu")
		(net "GND")
	)
	(segment
		(start 93.556074 -413.575754)
		(end 93.556074 -413.268668)
		(width 0.3556)
		(layer "F.Cu")
		(net "GND")
	)
	(segment
		(start 15.684246 -276.366732)
		(end 16.789146 -276.366732)
		(width 0.381)
		(layer "F.Cu")
		(net "GND")
	)
	(segment
		(start 449.677282 -233.86669)
		(end 448.572382 -233.86669)
		(width 0.381)
		(layer "F.Cu")
		(net "GND")
	)
	(segment
		(start 63.942214 -267.866622)
		(end 65.047114 -267.866622)
		(width 0.381)
		(layer "F.Cu")
		(net "GND")
	)
	(segment
		(start 128.196848 -286.7533)
		(end 128.196848 -287.288986)
		(width 0.254)
		(layer "F.Cu")
		(net "GND")
	)
	(segment
		(start 65.047114 -275.516594)
		(end 66.152014 -275.516594)
		(width 0.381)
		(layer "F.Cu")
		(net "GND")
	)
	(segment
		(start 346.799662 -39.360602)
		(end 346.384626 -38.945566)
		(width 0.2032)
		(layer "F.Cu")
		(net "GND")
	)
	(segment
		(start 350.292162 -285.939484)
		(end 350.292162 -286.475424)
		(width 0.2032)
		(layer "F.Cu")
		(net "GND")
	)
	(segment
		(start 337.495134 -225.739198)
		(end 337.495134 -225.203512)
		(width 0.2032)
		(layer "F.Cu")
		(net "GND")
	)
	(segment
		(start 452.016114 -276.366732)
		(end 450.911214 -276.366732)
		(width 0.381)
		(layer "F.Cu")
		(net "GND")
	)
	(segment
		(start 290.355782 -275.516594)
		(end 291.460682 -275.516594)
		(width 0.381)
		(layer "F.Cu")
		(net "GND")
	)
	(segment
		(start 441.028582 -210.066636)
		(end 442.133482 -210.066636)
		(width 0.381)
		(layer "F.Cu")
		(net "GND")
	)
	(segment
		(start 261.285482 -238.116618)
		(end 260.180582 -238.116618)
		(width 0.381)
		(layer "F.Cu")
		(net "GND")
	)
	(segment
		(start 328.194162 -54.902608)
		(end 328.244962 -54.953408)
		(width 0.2032)
		(layer "F.Cu")
		(net "GND")
	)
	(segment
		(start 271.168114 -289.11677)
		(end 270.063214 -289.11677)
		(width 0.381)
		(layer "F.Cu")
		(net "GND")
	)
	(segment
		(start 370.498116 -278.614378)
		(end 370.498116 -279.150064)
		(width 0.254)
		(layer "F.Cu")
		(net "GND")
	)
	(segment
		(start 309.992014 -223.666558)
		(end 308.887114 -223.666558)
		(width 0.381)
		(layer "F.Cu")
		(net "GND")
	)
	(segment
		(start 405.648414 -268.71676)
		(end 406.753314 -268.71676)
		(width 0.381)
		(layer "F.Cu")
		(net "GND")
	)
	(segment
		(start 444.472314 -199.01662)
		(end 443.367414 -199.01662)
		(width 0.381)
		(layer "F.Cu")
		(net "GND")
	)
	(segment
		(start 344.073734 -233.87812)
		(end 344.07348 -233.877866)
		(width 0.2032)
		(layer "F.Cu")
		(net "GND")
	)
	(segment
		(start 427.230032 -386.821934)
		(end 426.595032 -386.821934)
		(width 0.3556)
		(layer "F.Cu")
		(net "GND")
	)
	(segment
		(start 90.964512 -234.69219)
		(end 90.964766 -234.691936)
		(width 0.254)
		(layer "F.Cu")
		(net "GND")
	)
	(segment
		(start 30.771846 -233.016806)
		(end 31.876746 -233.016806)
		(width 0.381)
		(layer "F.Cu")
		(net "GND")
	)
	(segment
		(start 384.595116 -262.336534)
		(end 384.594862 -262.872474)
		(width 0.254)
		(layer "F.Cu")
		(net "GND")
	)
	(segment
		(start 183.929782 -35.887152)
		(end 183.878982 -35.836352)
		(width 0.3556)
		(layer "F.Cu")
		(net "GND")
	)
	(segment
		(start 406.753314 -298.466764)
		(end 407.858214 -298.466764)
		(width 0.381)
		(layer "F.Cu")
		(net "GND")
	)
	(segment
		(start 186.649614 -261.066788)
		(end 185.544714 -261.066788)
		(width 0.381)
		(layer "F.Cu")
		(net "GND")
	)
	(segment
		(start 102.352094 -278.336248)
		(end 102.352348 -278.336502)
		(width 0.254)
		(layer "F.Cu")
		(net "GND")
	)
	(segment
		(start 378.846334 -235.506006)
		(end 378.84608 -235.505752)
		(width 0.2032)
		(layer "F.Cu")
		(net "GND")
	)
	(segment
		(start 384.955034 -247.714008)
		(end 384.955034 -247.178322)
		(width 0.2032)
		(layer "F.Cu")
		(net "GND")
	)
	(segment
		(start 193.088514 -305.266598)
		(end 194.193414 -305.266598)
		(width 0.381)
		(layer "F.Cu")
		(net "GND")
	)
	(segment
		(start 131.016248 -284.033468)
		(end 131.015994 -284.033722)
		(width 0.254)
		(layer "F.Cu")
		(net "GND")
	)
	(segment
		(start 215.719914 -245.76659)
		(end 216.824814 -245.76659)
		(width 0.381)
		(layer "F.Cu")
		(net "GND")
	)
	(segment
		(start 110.340648 -287.288986)
		(end 110.340394 -287.28924)
		(width 0.254)
		(layer "F.Cu")
		(net "GND")
	)
	(segment
		(start 20.831556 -177.677318)
		(end 20.180554 -177.677318)
		(width 0.381)
		(layer "F.Cu")
		(net "GND")
	)
	(segment
		(start 363.33938 -229.808786)
		(end 363.339634 -229.808532)
		(width 0.2032)
		(layer "F.Cu")
		(net "GND")
	)
	(segment
		(start 301.343314 -301.866808)
		(end 302.448214 -301.866808)
		(width 0.381)
		(layer "F.Cu")
		(net "GND")
	)
	(segment
		(start 7.035546 -212.616796)
		(end 8.140446 -212.616796)
		(width 0.381)
		(layer "F.Cu")
		(net "GND")
	)
	(segment
		(start 131.016248 -254.197612)
		(end 131.016248 -254.733298)
		(width 0.254)
		(layer "F.Cu")
		(net "GND")
	)
	(segment
		(start 290.355782 -216.866724)
		(end 291.460682 -216.866724)
		(width 0.381)
		(layer "F.Cu")
		(net "GND")
	)
	(segment
		(start 86.265766 -247.178322)
		(end 86.265766 -247.714262)
		(width 0.2032)
		(layer "F.Cu")
		(net "GND")
	)
	(segment
		(start 456.116182 -226.216718)
		(end 455.011282 -226.216718)
		(width 0.381)
		(layer "F.Cu")
		(net "GND")
	)
	(segment
		(start 384.95478 -220.041978)
		(end 384.95478 -219.506038)
		(width 0.2032)
		(layer "F.Cu")
		(net "GND")
	)
	(segment
		(start 373.787162 -258.2672)
		(end 373.787162 -258.802886)
		(width 0.2032)
		(layer "F.Cu")
		(net "GND")
	)
	(segment
		(start 130.055112 -98.61042)
		(end 130.853942 -97.81159)
		(width 0.254)
		(layer "F.Cu")
		(net "GND")
	)
	(segment
		(start 93.894148 -269.661894)
		(end 93.894148 -270.19758)
		(width 0.2032)
		(layer "F.Cu")
		(net "GND")
	)
	(segment
		(start 429.384714 -265.316716)
		(end 430.489614 -265.316716)
		(width 0.381)
		(layer "F.Cu")
		(net "GND")
	)
	(segment
		(start 60.947046 -217.716608)
		(end 62.267846 -217.716608)
		(width 0.381)
		(layer "F.Cu")
		(net "GND")
	)
	(segment
		(start 132.785866 -220.855794)
		(end 132.785866 -220.319854)
		(width 0.2032)
		(layer "F.Cu")
		(net "GND")
	)
	(segment
		(start 65.047114 -230.466646)
		(end 66.152014 -230.466646)
		(width 0.381)
		(layer "F.Cu")
		(net "GND")
	)
	(segment
		(start 34.871914 -194.766692)
		(end 35.976814 -194.766692)
		(width 0.381)
		(layer "F.Cu")
		(net "GND")
	)
	(segment
		(start 92.954094 -276.708362)
		(end 92.954348 -276.708616)
		(width 0.2032)
		(layer "F.Cu")
		(net "GND")
	)
	(segment
		(start 341.72398 -233.064304)
		(end 341.724234 -233.06405)
		(width 0.254)
		(layer "F.Cu")
		(net "GND")
	)
	(segment
		(start 296.794682 -245.76659)
		(end 297.899582 -245.76659)
		(width 0.381)
		(layer "F.Cu")
		(net "GND")
	)
	(segment
		(start 286.255714 -296.766742)
		(end 287.360614 -296.766742)
		(width 0.381)
		(layer "F.Cu")
		(net "GND")
	)
	(segment
		(start 409.875482 -286.56661)
		(end 410.853382 -286.56661)
		(width 0.381)
		(layer "F.Cu")
		(net "GND")
	)
	(segment
		(start 45.657008 -11.26998)
		(end 45.657008 -12.37488)
		(width 0.3556)
		(layer "F.Cu")
		(net "GND")
	)
	(segment
		(start 380.725934 -246.900446)
		(end 380.72568 -246.900192)
		(width 0.2032)
		(layer "F.Cu")
		(net "GND")
	)
	(segment
		(start 261.285482 -306.96662)
		(end 260.180582 -306.96662)
		(width 0.381)
		(layer "F.Cu")
		(net "GND")
	)
	(segment
		(start 337.96478 -216.78646)
		(end 337.965034 -216.25052)
		(width 0.254)
		(layer "F.Cu")
		(net "GND")
	)
	(segment
		(start 42.415714 -210.066636)
		(end 41.310814 -210.066636)
		(width 0.381)
		(layer "F.Cu")
		(net "GND")
	)
	(segment
		(start 425.940982 -235.566712)
		(end 427.045882 -235.566712)
		(width 0.381)
		(layer "F.Cu")
		(net "GND")
	)
	(segment
		(start 210.514946 -214.316564)
		(end 211.619846 -214.316564)
		(width 0.381)
		(layer "F.Cu")
		(net "GND")
	)
	(segment
		(start 448.572382 -272.966688)
		(end 447.467482 -272.966688)
		(width 0.381)
		(layer "F.Cu")
		(net "GND")
	)
	(segment
		(start 178.000914 -224.516696)
		(end 176.896014 -224.516696)
		(width 0.381)
		(layer "F.Cu")
		(net "GND")
	)
	(segment
		(start 271.168114 -270.416782)
		(end 270.063214 -270.416782)
		(width 0.381)
		(layer "F.Cu")
		(net "GND")
	)
	(segment
		(start 382.245362 -276.172676)
		(end 382.245616 -276.708616)
		(width 0.2032)
		(layer "F.Cu")
		(net "GND")
	)
	(segment
		(start 26.223214 -282.316682)
		(end 27.328114 -282.316682)
		(width 0.381)
		(layer "F.Cu")
		(net "GND")
	)
	(segment
		(start 94.833694 -258.2672)
		(end 94.833694 -258.80314)
		(width 0.2032)
		(layer "F.Cu")
		(net "GND")
	)
	(segment
		(start 178.000914 -249.166634)
		(end 176.896014 -249.166634)
		(width 0.381)
		(layer "F.Cu")
		(net "GND")
	)
	(segment
		(start 7.035546 -307.816758)
		(end 8.140446 -307.816758)
		(width 0.381)
		(layer "F.Cu")
		(net "GND")
	)
	(segment
		(start 307.782214 -289.11677)
		(end 308.887114 -289.11677)
		(width 0.381)
		(layer "F.Cu")
		(net "GND")
	)
	(segment
		(start 135.605266 -233.34218)
		(end 135.605266 -233.87812)
		(width 0.2032)
		(layer "F.Cu")
		(net "GND")
	)
	(segment
		(start 419.761416 -312.91657)
		(end 418.397182 -312.91657)
		(width 0.381)
		(layer "F.Cu")
		(net "GND")
	)
	(segment
		(start 170.457114 -306.96662)
		(end 169.352214 -306.96662)
		(width 0.381)
		(layer "F.Cu")
		(net "GND")
	)
	(segment
		(start 86.526116 -92.238322)
		(end 87.226394 -92.238322)
		(width 0.3556)
		(layer "F.Cu")
		(net "GND")
	)
	(segment
		(start 337.900264 -57.605168)
		(end 338.40039 -57.45734)
		(width 0.254)
		(layer "F.Cu")
		(net "GND")
	)
	(segment
		(start 166.357046 -242.3668)
		(end 165.252146 -242.3668)
		(width 0.381)
		(layer "F.Cu")
		(net "GND")
	)
	(segment
		(start 102.822248 -281.869896)
		(end 102.822248 -282.405836)
		(width 0.2032)
		(layer "F.Cu")
		(net "GND")
	)
	(segment
		(start 18.679414 -316.316614)
		(end 19.784314 -316.316614)
		(width 0.381)
		(layer "F.Cu")
		(net "GND")
	)
	(segment
		(start 261.285482 -194.766692)
		(end 260.180582 -194.766692)
		(width 0.381)
		(layer "F.Cu")
		(net "GND")
	)
	(segment
		(start 278.711914 -208.366614)
		(end 279.816814 -208.366614)
		(width 0.381)
		(layer "F.Cu")
		(net "GND")
	)
	(segment
		(start 282.811982 -196.466714)
		(end 283.916882 -196.466714)
		(width 0.381)
		(layer "F.Cu")
		(net "GND")
	)
	(segment
		(start 350.762062 -268.847824)
		(end 350.762062 -269.38351)
		(width 0.2032)
		(layer "F.Cu")
		(net "GND")
	)
	(segment
		(start 410.853382 -245.76659)
		(end 411.958282 -245.76659)
		(width 0.381)
		(layer "F.Cu")
		(net "GND")
	)
	(segment
		(start 410.853382 -205.816708)
		(end 412.238444 -205.816708)
		(width 0.381)
		(layer "F.Cu")
		(net "GND")
	)
	(segment
		(start 262.519414 -301.866808)
		(end 263.624314 -301.866808)
		(width 0.381)
		(layer "F.Cu")
		(net "GND")
	)
	(segment
		(start 296.794682 -314.616592)
		(end 297.899582 -314.616592)
		(width 0.381)
		(layer "F.Cu")
		(net "GND")
	)
	(segment
		(start 443.367414 -242.3668)
		(end 444.472314 -242.3668)
		(width 0.381)
		(layer "F.Cu")
		(net "GND")
	)
	(segment
		(start 335.67878 -55.498746)
		(end 335.138268 -55.498746)
		(width 0.2032)
		(layer "F.Cu")
		(net "GND")
	)
	(segment
		(start 33.767014 -233.86669)
		(end 34.871914 -233.86669)
		(width 0.381)
		(layer "F.Cu")
		(net "GND")
	)
	(segment
		(start 191.983614 -267.866622)
		(end 193.088514 -267.866622)
		(width 0.381)
		(layer "F.Cu")
		(net "GND")
	)
	(segment
		(start 196.532246 -223.666558)
		(end 197.637146 -223.666558)
		(width 0.381)
		(layer "F.Cu")
		(net "GND")
	)
	(segment
		(start 42.415714 -205.816708)
		(end 41.310814 -205.816708)
		(width 0.381)
		(layer "F.Cu")
		(net "GND")
	)
	(segment
		(start 368.618262 -264.500106)
		(end 368.618262 -264.50036)
		(width 0.2032)
		(layer "F.Cu")
		(net "GND")
	)
	(segment
		(start 129.136648 -265.592306)
		(end 129.136648 -266.127992)
		(width 0.254)
		(layer "F.Cu")
		(net "GND")
	)
	(segment
		(start 172.795946 -208.366614)
		(end 173.900846 -208.366614)
		(width 0.381)
		(layer "F.Cu")
		(net "GND")
	)
	(segment
		(start 166.357046 -210.916774)
		(end 167.461946 -210.916774)
		(width 0.381)
		(layer "F.Cu")
		(net "GND")
	)
	(segment
		(start 100.362512 -247.178576)
		(end 100.362766 -247.178322)
		(width 0.2032)
		(layer "F.Cu")
		(net "GND")
	)
	(segment
		(start 27.328114 -249.166634)
		(end 26.223214 -249.166634)
		(width 0.381)
		(layer "F.Cu")
		(net "GND")
	)
	(segment
		(start 363.80928 -233.877866)
		(end 363.80928 -233.34218)
		(width 0.2032)
		(layer "F.Cu")
		(net "GND")
	)
	(segment
		(start 27.328114 -308.666642)
		(end 28.433014 -308.666642)
		(width 0.381)
		(layer "F.Cu")
		(net "GND")
	)
	(segment
		(start 173.900846 -227.066602)
		(end 172.795946 -227.066602)
		(width 0.381)
		(layer "F.Cu")
		(net "GND")
	)
	(segment
		(start 119.738648 -266.127992)
		(end 119.738394 -266.128246)
		(width 0.254)
		(layer "F.Cu")
		(net "GND")
	)
	(segment
		(start 84.966048 -265.592306)
		(end 84.495894 -265.314176)
		(width 0.254)
		(layer "F.Cu")
		(net "GND")
	)
	(segment
		(start 87.205312 -232.528618)
		(end 87.205566 -232.528364)
		(width 0.254)
		(layer "F.Cu")
		(net "GND")
	)
	(segment
		(start 294.904414 -212.616796)
		(end 293.799514 -212.616796)
		(width 0.381)
		(layer "F.Cu")
		(net "GND")
	)
	(segment
		(start 176.57953 -421.350948)
		(end 177.18913 -421.350948)
		(width 0.3556)
		(layer "F.Cu")
		(net "GND")
	)
	(segment
		(start 193.088514 -211.766658)
		(end 191.983614 -211.766658)
		(width 0.381)
		(layer "F.Cu")
		(net "GND")
	)
	(segment
		(start 277.607014 -281.466798)
		(end 278.711914 -281.466798)
		(width 0.381)
		(layer "F.Cu")
		(net "GND")
	)
	(segment
		(start 275.268182 -235.566712)
		(end 274.163282 -235.566712)
		(width 0.381)
		(layer "F.Cu")
		(net "GND")
	)
	(segment
		(start 176.896014 -275.516594)
		(end 178.000914 -275.516594)
		(width 0.381)
		(layer "F.Cu")
		(net "GND")
	)
	(segment
		(start 131.375912 -222.76181)
		(end 131.376166 -222.761556)
		(width 0.254)
		(layer "F.Cu")
		(net "GND")
	)
	(segment
		(start 55.066946 -12.37488)
		(end 55.066946 -11.26998)
		(width 0.3556)
		(layer "F.Cu")
		(net "GND")
	)
	(segment
		(start 271.168114 -301.866808)
		(end 270.063214 -301.866808)
		(width 0.381)
		(layer "F.Cu")
		(net "GND")
	)
	(segment
		(start 441.028582 -303.566576)
		(end 442.133482 -303.566576)
		(width 0.381)
		(layer "F.Cu")
		(net "GND")
	)
	(segment
		(start 85.435694 -255.011682)
		(end 85.905594 -254.733552)
		(width 0.254)
		(layer "F.Cu")
		(net "GND")
	)
	(segment
		(start 394.84681 -11.26998)
		(end 394.84681 -10.16508)
		(width 0.3556)
		(layer "F.Cu")
		(net "GND")
	)
	(segment
		(start 449.677282 -210.066636)
		(end 448.572382 -210.066636)
		(width 0.381)
		(layer "F.Cu")
		(net "GND")
	)
	(segment
		(start 98.482912 -237.947454)
		(end 98.482912 -237.411514)
		(width 0.254)
		(layer "F.Cu")
		(net "GND")
	)
	(segment
		(start 337.699858 -45.249846)
		(end 338.099908 -44.849796)
		(width 0.2032)
		(layer "F.Cu")
		(net "GND")
	)
	(segment
		(start 418.397182 -294.216582)
		(end 417.089082 -294.216582)
		(width 0.381)
		(layer "F.Cu")
		(net "GND")
	)
	(segment
		(start 207.071214 -305.266598)
		(end 208.176114 -305.266598)
		(width 0.381)
		(layer "F.Cu")
		(net "GND")
	)
	(segment
		(start 185.544714 -202.416664)
		(end 186.649614 -202.416664)
		(width 0.381)
		(layer "F.Cu")
		(net "GND")
	)
	(segment
		(start 102.712012 -233.877866)
		(end 102.712012 -233.34218)
		(width 0.2032)
		(layer "F.Cu")
		(net "GND")
	)
	(segment
		(start 42.415714 -267.866622)
		(end 41.310814 -267.866622)
		(width 0.381)
		(layer "F.Cu")
		(net "GND")
	)
	(segment
		(start 405.648414 -210.916774)
		(end 406.753314 -210.916774)
		(width 0.381)
		(layer "F.Cu")
		(net "GND")
	)
	(segment
		(start 256.080514 -276.366732)
		(end 257.185414 -276.366732)
		(width 0.381)
		(layer "F.Cu")
		(net "GND")
	)
	(segment
		(start 210.514946 -261.916672)
		(end 211.619846 -261.916672)
		(width 0.381)
		(layer "F.Cu")
		(net "GND")
	)
	(segment
		(start 305.443382 -277.216616)
		(end 306.548282 -277.216616)
		(width 0.381)
		(layer "F.Cu")
		(net "GND")
	)
	(segment
		(start 56.398414 -282.316682)
		(end 57.503314 -282.316682)
		(width 0.381)
		(layer "F.Cu")
		(net "GND")
	)
	(segment
		(start 373.317516 -262.336534)
		(end 373.317516 -262.872474)
		(width 0.2032)
		(layer "F.Cu")
		(net "GND")
	)
	(segment
		(start 343.13368 -235.505752)
		(end 343.13368 -234.970066)
		(width 0.2032)
		(layer "F.Cu")
		(net "GND")
	)
	(segment
		(start 138.064494 -272.917158)
		(end 137.594594 -272.639282)
		(width 0.254)
		(layer "F.Cu")
		(net "GND")
	)
	(segment
		(start 449.072508 -92.493592)
		(end 449.71208 -92.493592)
		(width 0.3556)
		(layer "F.Cu")
		(net "GND")
	)
	(segment
		(start 187.883546 -301.866808)
		(end 188.988446 -301.866808)
		(width 0.381)
		(layer "F.Cu")
		(net "GND")
	)
	(segment
		(start 334.675734 -245.27256)
		(end 335.145634 -245.55069)
		(width 0.254)
		(layer "F.Cu")
		(net "GND")
	)
	(segment
		(start 63.942214 -288.266632)
		(end 65.047114 -288.266632)
		(width 0.381)
		(layer "F.Cu")
		(net "GND")
	)
	(segment
		(start 94.254066 -242.017042)
		(end 94.254066 -241.481102)
		(width 0.2032)
		(layer "F.Cu")
		(net "GND")
	)
	(segment
		(start 86.375494 -281.05608)
		(end 86.375494 -281.59202)
		(width 0.2032)
		(layer "F.Cu")
		(net "GND")
	)
	(segment
		(start 261.285482 -308.666642)
		(end 260.180582 -308.666642)
		(width 0.381)
		(layer "F.Cu")
		(net "GND")
	)
	(segment
		(start 296.794682 -308.666642)
		(end 297.899582 -308.666642)
		(width 0.381)
		(layer "F.Cu")
		(net "GND")
	)
	(segment
		(start 362.399834 -226.017328)
		(end 362.399834 -226.553268)
		(width 0.254)
		(layer "F.Cu")
		(net "GND")
	)
	(segment
		(start 342.90254 -37.160454)
		(end 342.90254 -37.63518)
		(width 0.2032)
		(layer "F.Cu")
		(net "GND")
	)
	(segment
		(start 433.484782 -277.216616)
		(end 434.589682 -277.216616)
		(width 0.381)
		(layer "F.Cu")
		(net "GND")
	)
	(segment
		(start 53.403246 -208.366614)
		(end 52.082446 -208.366614)
		(width 0.381)
		(layer "F.Cu")
		(net "GND")
	)
	(segment
		(start 126.207266 -243.644928)
		(end 126.207266 -243.108988)
		(width 0.2032)
		(layer "F.Cu")
		(net "GND")
	)
	(segment
		(start 110.230666 -220.855794)
		(end 110.230666 -220.319854)
		(width 0.2032)
		(layer "F.Cu")
		(net "GND")
	)
	(segment
		(start 33.767014 -264.466578)
		(end 34.871914 -264.466578)
		(width 0.381)
		(layer "F.Cu")
		(net "GND")
	)
	(segment
		(start 111.640112 -222.76181)
		(end 111.640366 -222.761556)
		(width 0.254)
		(layer "F.Cu")
		(net "GND")
	)
	(segment
		(start 111.690912 -398.85874)
		(end 111.690912 -399.409666)
		(width 0.3556)
		(layer "F.Cu")
		(net "GND")
	)
	(segment
		(start 157.708346 -296.766742)
		(end 158.813246 -296.766742)
		(width 0.381)
		(layer "F.Cu")
		(net "GND")
	)
	(segment
		(start 312.987182 -280.61666)
		(end 314.092082 -280.61666)
		(width 0.381)
		(layer "F.Cu")
		(net "GND")
	)
	(segment
		(start 424.836082 -264.466578)
		(end 425.940982 -264.466578)
		(width 0.381)
		(layer "F.Cu")
		(net "GND")
	)
	(segment
		(start 457.221082 -314.616592)
		(end 456.116182 -314.616592)
		(width 0.381)
		(layer "F.Cu")
		(net "GND")
	)
	(segment
		(start 223.868488 -233.17962)
		(end 223.868488 -233.84637)
		(width 0.3556)
		(layer "F.Cu")
		(net "GND")
	)
	(segment
		(start 134.195566 -237.947454)
		(end 134.195566 -237.411514)
		(width 0.254)
		(layer "F.Cu")
		(net "GND")
	)
	(segment
		(start 99.422712 -241.203226)
		(end 99.422966 -241.202972)
		(width 0.2032)
		(layer "F.Cu")
		(net "GND")
	)
	(segment
		(start 300.99762 -414.156144)
		(end 300.99762 -414.78454)
		(width 0.3556)
		(layer "F.Cu")
		(net "GND")
	)
	(segment
		(start 425.940982 -269.566644)
		(end 427.045882 -269.566644)
		(width 0.381)
		(layer "F.Cu")
		(net "GND")
	)
	(segment
		(start 161.73577 -216.866724)
		(end 161.697924 -216.90457)
		(width 0.381)
		(layer "F.Cu")
		(net "GND")
	)
	(segment
		(start 97.653094 -276.172676)
		(end 97.653094 -276.708616)
		(width 0.2032)
		(layer "F.Cu")
		(net "GND")
	)
	(segment
		(start 54.42458 -153.739088)
		(end 54.807358 -153.35631)
		(width 0.2032)
		(layer "F.Cu")
		(net "GND")
	)
	(segment
		(start 135.12292 -46.715934)
		(end 134.48792 -46.715934)
		(width 0.3556)
		(layer "F.Cu")
		(net "GND")
	)
	(segment
		(start 343.60358 -216.78646)
		(end 343.60358 -216.250774)
		(width 0.254)
		(layer "F.Cu")
		(net "GND")
	)
	(segment
		(start 208.176114 -224.516696)
		(end 209.281014 -224.516696)
		(width 0.381)
		(layer "F.Cu")
		(net "GND")
	)
	(segment
		(start 154.87904 -47.523908)
		(end 154.87904 -46.751748)
		(width 0.3556)
		(layer "F.Cu")
		(net "GND")
	)
	(segment
		(start 433.484782 -204.116686)
		(end 434.589682 -204.116686)
		(width 0.381)
		(layer "F.Cu")
		(net "GND")
	)
	(segment
		(start 165.78072 -22.473158)
		(end 166.07028 -22.183598)
		(width 0.3556)
		(layer "F.Cu")
		(net "GND")
	)
	(segment
		(start 370.498116 -259.081016)
		(end 370.498116 -259.093462)
		(width 0.254)
		(layer "F.Cu")
		(net "GND")
	)
	(segment
		(start 278.711914 -236.416596)
		(end 279.816814 -236.416596)
		(width 0.381)
		(layer "F.Cu")
		(net "GND")
	)
	(segment
		(start 364.389162 -288.102802)
		(end 364.389416 -288.103056)
		(width 0.254)
		(layer "F.Cu")
		(net "GND")
	)
	(segment
		(start 99.422712 -226.553268)
		(end 99.422712 -226.017582)
		(width 0.254)
		(layer "F.Cu")
		(net "GND")
	)
	(segment
		(start 419.502082 -261.066788)
		(end 418.397182 -261.066788)
		(width 0.381)
		(layer "F.Cu")
		(net "GND")
	)
	(segment
		(start 119.158766 -220.041724)
		(end 119.158766 -219.506038)
		(width 0.254)
		(layer "F.Cu")
		(net "GND")
	)
	(segment
		(start 42.415714 -306.96662)
		(end 41.310814 -306.96662)
		(width 0.381)
		(layer "F.Cu")
		(net "GND")
	)
	(segment
		(start 199.527414 -261.066788)
		(end 200.632314 -261.066788)
		(width 0.381)
		(layer "F.Cu")
		(net "GND")
	)
	(segment
		(start 383.075434 -247.714008)
		(end 383.075434 -247.178322)
		(width 0.2032)
		(layer "F.Cu")
		(net "GND")
	)
	(segment
		(start 8.140446 -265.316716)
		(end 9.245346 -265.316716)
		(width 0.381)
		(layer "F.Cu")
		(net "GND")
	)
	(segment
		(start 462.555082 -230.466646)
		(end 463.659982 -230.466646)
		(width 0.381)
		(layer "F.Cu")
		(net "GND")
	)
	(segment
		(start 114.099848 -265.592306)
		(end 114.099848 -266.127992)
		(width 0.254)
		(layer "F.Cu")
		(net "GND")
	)
	(segment
		(start 277.607014 -267.016738)
		(end 278.711914 -267.016738)
		(width 0.381)
		(layer "F.Cu")
		(net "GND")
	)
	(segment
		(start 18.679414 -284.866588)
		(end 19.784314 -284.866588)
		(width 0.381)
		(layer "F.Cu")
		(net "GND")
	)
	(segment
		(start 166.357046 -300.166786)
		(end 165.252146 -300.166786)
		(width 0.381)
		(layer "F.Cu")
		(net "GND")
	)
	(segment
		(start 158.2801 -69.385688)
		(end 157.801818 -69.86397)
		(width 0.3556)
		(layer "F.Cu")
		(net "GND")
	)
	(segment
		(start 202.971146 -250.016772)
		(end 204.076046 -250.016772)
		(width 0.381)
		(layer "F.Cu")
		(net "GND")
	)
	(segment
		(start 290.355782 -219.41663)
		(end 291.460682 -219.41663)
		(width 0.381)
		(layer "F.Cu")
		(net "GND")
	)
	(segment
		(start 408.061414 -272.116804)
		(end 406.753314 -272.116804)
		(width 0.381)
		(layer "F.Cu")
		(net "GND")
	)
	(segment
		(start 450.911214 -292.516814)
		(end 452.016114 -292.516814)
		(width 0.381)
		(layer "F.Cu")
		(net "GND")
	)
	(segment
		(start 46.964346 -298.466764)
		(end 45.859446 -298.466764)
		(width 0.381)
		(layer "F.Cu")
		(net "GND")
	)
	(segment
		(start 262.519414 -201.56678)
		(end 263.624314 -201.56678)
		(width 0.381)
		(layer "F.Cu")
		(net "GND")
	)
	(segment
		(start 387.408928 -246.900446)
		(end 387.550914 -247.042432)
		(width 0.2032)
		(layer "F.Cu")
		(net "GND")
	)
	(segment
		(start 95.193866 -224.111566)
		(end 95.193866 -223.575626)
		(width 0.2032)
		(layer "F.Cu")
		(net "GND")
	)
	(segment
		(start 334.315562 -261.522718)
		(end 335.255362 -262.058658)
		(width 0.254)
		(layer "F.Cu")
		(net "GND")
	)
	(segment
		(start 377.546362 -256.639314)
		(end 377.546362 -256.807462)
		(width 0.2032)
		(layer "F.Cu")
		(net "GND")
	)
	(segment
		(start 375.197116 -279.150064)
		(end 375.196862 -279.150318)
		(width 0.254)
		(layer "F.Cu")
		(net "GND")
	)
	(segment
		(start 99.35464 -96.773492)
		(end 99.974654 -96.773492)
		(width 0.3556)
		(layer "F.Cu")
		(net "GND")
	)
	(segment
		(start 459.559914 -206.666592)
		(end 458.455014 -206.666592)
		(width 0.381)
		(layer "F.Cu")
		(net "GND")
	)
	(segment
		(start 116.339112 -226.553268)
		(end 116.339112 -226.017582)
		(width 0.254)
		(layer "F.Cu")
		(net "GND")
	)
	(segment
		(start 67.812412 -39.421562)
		(end 67.202812 -39.421562)
		(width 0.3556)
		(layer "F.Cu")
		(net "GND")
	)
	(segment
		(start 38.315646 -201.56678)
		(end 37.210746 -201.56678)
		(width 0.381)
		(layer "F.Cu")
		(net "GND")
	)
	(segment
		(start 49.959514 -280.61666)
		(end 51.064414 -280.61666)
		(width 0.381)
		(layer "F.Cu")
		(net "GND")
	)
	(segment
		(start 106.001312 -226.553268)
		(end 106.001312 -226.017582)
		(width 0.254)
		(layer "F.Cu")
		(net "GND")
	)
	(segment
		(start 188.988446 -309.51678)
		(end 190.093346 -309.51678)
		(width 0.381)
		(layer "F.Cu")
		(net "GND")
	)
	(segment
		(start 419.502082 -303.566576)
		(end 418.397182 -303.566576)
		(width 0.381)
		(layer "F.Cu")
		(net "GND")
	)
	(segment
		(start 137.484866 -222.48368)
		(end 137.484866 -221.94774)
		(width 0.2032)
		(layer "F.Cu")
		(net "GND")
	)
	(segment
		(start 191.983614 -288.266632)
		(end 193.088514 -288.266632)
		(width 0.381)
		(layer "F.Cu")
		(net "GND")
	)
	(segment
		(start 90.964512 -226.553268)
		(end 90.964512 -226.017328)
		(width 0.254)
		(layer "F.Cu")
		(net "GND")
	)
	(segment
		(start 336.555334 -235.506006)
		(end 336.55508 -235.505752)
		(width 0.2032)
		(layer "F.Cu")
		(net "GND")
	)
	(segment
		(start 92.484448 -281.869896)
		(end 92.484702 -281.87015)
		(width 0.254)
		(layer "F.Cu")
		(net "GND")
	)
	(segment
		(start 22.409404 -107.777026)
		(end 21.799804 -107.777026)
		(width 0.3556)
		(layer "F.Cu")
		(net "GND")
	)
	(segment
		(start 435.823614 -268.71676)
		(end 436.928514 -268.71676)
		(width 0.381)
		(layer "F.Cu")
		(net "GND")
	)
	(segment
		(start 22.123146 -307.816758)
		(end 23.228046 -307.816758)
		(width 0.381)
		(layer "F.Cu")
		(net "GND")
	)
	(segment
		(start 382.245362 -288.102802)
		(end 382.245616 -288.103056)
		(width 0.254)
		(layer "F.Cu")
		(net "GND")
	)
	(segment
		(start 57.503314 -213.46668)
		(end 58.608214 -213.46668)
		(width 0.381)
		(layer "F.Cu")
		(net "GND")
	)
	(segment
		(start 19.784314 -282.316682)
		(end 20.889214 -282.316682)
		(width 0.381)
		(layer "F.Cu")
		(net "GND")
	)
	(segment
		(start 380.725934 -233.87812)
		(end 380.725934 -233.34218)
		(width 0.2032)
		(layer "F.Cu")
		(net "GND")
	)
	(segment
		(start 336.49285 -40.931846)
		(end 335.953608 -40.931846)
		(width 0.2032)
		(layer "F.Cu")
		(net "GND")
	)
	(segment
		(start 348.30258 -226.017582)
		(end 348.302834 -226.017328)
		(width 0.254)
		(layer "F.Cu")
		(net "GND")
	)
	(segment
		(start 453.121014 -195.616576)
		(end 452.016114 -195.616576)
		(width 0.381)
		(layer "F.Cu")
		(net "GND")
	)
	(segment
		(start 193.088514 -221.116652)
		(end 191.983614 -221.116652)
		(width 0.381)
		(layer "F.Cu")
		(net "GND")
	)
	(segment
		(start 439.923682 -239.81664)
		(end 441.028582 -239.81664)
		(width 0.381)
		(layer "F.Cu")
		(net "GND")
	)
	(segment
		(start 137.02411 -26.269188)
		(end 137.02411 -27.447748)
		(width 0.3556)
		(layer "F.Cu")
		(net "GND")
	)
	(segment
		(start 215.719914 -277.216616)
		(end 216.824814 -277.216616)
		(width 0.381)
		(layer "F.Cu")
		(net "GND")
	)
	(segment
		(start 308.887114 -287.416748)
		(end 307.566314 -287.416748)
		(width 0.381)
		(layer "F.Cu")
		(net "GND")
	)
	(segment
		(start 214.88654 -128.432814)
		(end 215.57234 -128.432814)
		(width 0.3556)
		(layer "F.Cu")
		(net "GND")
	)
	(segment
		(start 167.461946 -301.866808)
		(end 166.357046 -301.866808)
		(width 0.381)
		(layer "F.Cu")
		(net "GND")
	)
	(segment
		(start 211.619846 -231.316784)
		(end 210.514946 -231.316784)
		(width 0.381)
		(layer "F.Cu")
		(net "GND")
	)
	(segment
		(start 97.543112 -236.319822)
		(end 97.543112 -235.783882)
		(width 0.2032)
		(layer "F.Cu")
		(net "GND")
	)
	(segment
		(start 98.592894 -279.96388)
		(end 98.593148 -279.964134)
		(width 0.254)
		(layer "F.Cu")
		(net "GND")
	)
	(segment
		(start 345.593162 -271.289272)
		(end 345.593162 -271.825212)
		(width 0.2032)
		(layer "F.Cu")
		(net "GND")
	)
	(segment
		(start 222.07093 -42.255948)
		(end 222.07093 -41.620948)
		(width 0.3556)
		(layer "F.Cu")
		(net "GND")
	)
	(segment
		(start 150.697946 -39.561262)
		(end 150.697946 -38.75405)
		(width 0.3556)
		(layer "F.Cu")
		(net "GND")
	)
	(segment
		(start 44.754546 -304.416714)
		(end 45.859446 -304.416714)
		(width 0.381)
		(layer "F.Cu")
		(net "GND")
	)
	(segment
		(start 350.652334 -220.855794)
		(end 350.652334 -220.319854)
		(width 0.2032)
		(layer "F.Cu")
		(net "GND")
	)
	(segment
		(start 14.579346 -268.71676)
		(end 15.684246 -268.71676)
		(width 0.381)
		(layer "F.Cu")
		(net "GND")
	)
	(segment
		(start 271.168114 -258.516628)
		(end 272.273014 -258.516628)
		(width 0.381)
		(layer "F.Cu")
		(net "GND")
	)
	(segment
		(start 188.988446 -263.616694)
		(end 187.883546 -263.616694)
		(width 0.381)
		(layer "F.Cu")
		(net "GND")
	)
	(segment
		(start 46.750478 -97.808034)
		(end 47.360078 -97.808034)
		(width 0.3556)
		(layer "F.Cu")
		(net "GND")
	)
	(segment
		(start 99.532694 -265.313922)
		(end 99.532948 -265.314176)
		(width 0.2032)
		(layer "F.Cu")
		(net "GND")
	)
	(segment
		(start 111.170466 -225.739198)
		(end 111.170466 -225.203512)
		(width 0.254)
		(layer "F.Cu")
		(net "GND")
	)
	(segment
		(start 196.532246 -201.56678)
		(end 197.637146 -201.56678)
		(width 0.381)
		(layer "F.Cu")
		(net "GND")
	)
	(segment
		(start 45.859446 -246.616728)
		(end 46.964346 -246.616728)
		(width 0.381)
		(layer "F.Cu")
		(net "GND")
	)
	(segment
		(start 31.147004 -11.26998)
		(end 31.147004 -12.37488)
		(width 0.3556)
		(layer "F.Cu")
		(net "GND")
	)
	(segment
		(start 384.485134 -230.086662)
		(end 384.485134 -230.622602)
		(width 0.254)
		(layer "F.Cu")
		(net "GND")
	)
	(segment
		(start 260.180582 -216.866724)
		(end 259.075682 -216.866724)
		(width 0.381)
		(layer "F.Cu")
		(net "GND")
	)
	(segment
		(start 266.619482 -210.066636)
		(end 267.724382 -210.066636)
		(width 0.381)
		(layer "F.Cu")
		(net "GND")
	)
	(segment
		(start 140.54709 -17.655032)
		(end 140.54709 -16.550132)
		(width 0.3556)
		(layer "F.Cu")
		(net "GND")
	)
	(segment
		(start 47.360078 -99.840034)
		(end 47.311564 -99.79152)
		(width 0.3556)
		(layer "F.Cu")
		(net "GND")
	)
	(segment
		(start 85.435694 -282.683966)
		(end 85.435694 -283.219906)
		(width 0.2032)
		(layer "F.Cu")
		(net "GND")
	)
	(segment
		(start 423.199814 -292.516814)
		(end 421.840914 -292.516814)
		(width 0.381)
		(layer "F.Cu")
		(net "GND")
	)
	(segment
		(start 263.624314 -268.71676)
		(end 264.729214 -268.71676)
		(width 0.381)
		(layer "F.Cu")
		(net "GND")
	)
	(segment
		(start 169.75328 -436.971948)
		(end 169.36593 -436.971948)
		(width 0.3556)
		(layer "F.Cu")
		(net "GND")
	)
	(segment
		(start 464.764882 -275.516594)
		(end 463.659982 -275.516594)
		(width 0.381)
		(layer "F.Cu")
		(net "GND")
	)
	(segment
		(start 215.719914 -230.466646)
		(end 216.824814 -230.466646)
		(width 0.381)
		(layer "F.Cu")
		(net "GND")
	)
	(segment
		(start 290.355782 -261.066788)
		(end 291.460682 -261.066788)
		(width 0.381)
		(layer "F.Cu")
		(net "GND")
	)
	(segment
		(start 199.527414 -200.716642)
		(end 200.632314 -200.716642)
		(width 0.381)
		(layer "F.Cu")
		(net "GND")
	)
	(segment
		(start 345.953334 -238.761524)
		(end 345.953334 -238.225584)
		(width 0.2032)
		(layer "F.Cu")
		(net "GND")
	)
	(segment
		(start 456.116182 -297.616626)
		(end 455.011282 -297.616626)
		(width 0.381)
		(layer "F.Cu")
		(net "GND")
	)
	(segment
		(start 42.415714 -207.51673)
		(end 41.310814 -207.51673)
		(width 0.381)
		(layer "F.Cu")
		(net "GND")
	)
	(segment
		(start 434.57368 -20.869148)
		(end 434.805328 -20.6375)
		(width 0.3556)
		(layer "F.Cu")
		(net "GND")
	)
	(segment
		(start 184.439814 -235.566712)
		(end 185.544714 -235.566712)
		(width 0.381)
		(layer "F.Cu")
		(net "GND")
	)
	(segment
		(start 110.340648 -271.011142)
		(end 110.340394 -271.011396)
		(width 0.254)
		(layer "F.Cu")
		(net "GND")
	)
	(segment
		(start 355.461316 -280.242264)
		(end 355.461316 -280.77795)
		(width 0.254)
		(layer "F.Cu")
		(net "GND")
	)
	(segment
		(start 343.006934 -50.329592)
		(end 343.005156 -50.329846)
		(width 0.254)
		(layer "F.Cu")
		(net "GND")
	)
	(segment
		(start 463.659982 -202.416664)
		(end 464.764882 -202.416664)
		(width 0.381)
		(layer "F.Cu")
		(net "GND")
	)
	(segment
		(start 116.339112 -220.041978)
		(end 116.339366 -220.041724)
		(width 0.254)
		(layer "F.Cu")
		(net "GND")
	)
	(segment
		(start 352.06178 -223.297496)
		(end 352.06178 -222.76181)
		(width 0.254)
		(layer "F.Cu")
		(net "GND")
	)
	(segment
		(start 458.455014 -273.816572)
		(end 459.559914 -273.816572)
		(width 0.381)
		(layer "F.Cu")
		(net "GND")
	)
	(segment
		(start 285.150814 -304.416714)
		(end 286.255714 -304.416714)
		(width 0.381)
		(layer "F.Cu")
		(net "GND")
	)
	(segment
		(start 338.90458 -246.08663)
		(end 338.90458 -245.55069)
		(width 0.2032)
		(layer "F.Cu")
		(net "GND")
	)
	(segment
		(start 92.954348 -268.034008)
		(end 92.954348 -268.569694)
		(width 0.2032)
		(layer "F.Cu")
		(net "GND")
	)
	(segment
		(start 129.496312 -239.57534)
		(end 129.496312 -239.0394)
		(width 0.2032)
		(layer "F.Cu")
		(net "GND")
	)
	(segment
		(start 58.0517 -107.500674)
		(end 58.202322 -107.651296)
		(width 0.3556)
		(layer "F.Cu")
		(net "GND")
	)
	(segment
		(start 341.918798 -42.811446)
		(end 342.190578 -43.281346)
		(width 0.254)
		(layer "F.Cu")
		(net "GND")
	)
	(segment
		(start 427.045882 -272.966688)
		(end 425.940982 -272.966688)
		(width 0.381)
		(layer "F.Cu")
		(net "GND")
	)
	(segment
		(start 42.415714 -312.91657)
		(end 41.310814 -312.91657)
		(width 0.381)
		(layer "F.Cu")
		(net "GND")
	)
	(segment
		(start 42.415714 -233.86669)
		(end 41.310814 -233.86669)
		(width 0.381)
		(layer "F.Cu")
		(net "GND")
	)
	(segment
		(start 7.035546 -276.366732)
		(end 8.140446 -276.366732)
		(width 0.381)
		(layer "F.Cu")
		(net "GND")
	)
	(segment
		(start 129.136648 -255.825498)
		(end 129.136648 -256.361438)
		(width 0.2032)
		(layer "F.Cu")
		(net "GND")
	)
	(segment
		(start 275.268182 -305.266598)
		(end 274.163282 -305.266598)
		(width 0.381)
		(layer "F.Cu")
		(net "GND")
	)
	(segment
		(start 8.140446 -223.666558)
		(end 9.245346 -223.666558)
		(width 0.381)
		(layer "F.Cu")
		(net "GND")
	)
	(segment
		(start 347.003116 -280.242264)
		(end 347.002862 -280.778204)
		(width 0.254)
		(layer "F.Cu")
		(net "GND")
	)
	(segment
		(start 336.555334 -220.855794)
		(end 336.555334 -220.319854)
		(width 0.2032)
		(layer "F.Cu")
		(net "GND")
	)
	(segment
		(start 339.484716 -275.35886)
		(end 339.484716 -275.894546)
		(width 0.2032)
		(layer "F.Cu")
		(net "GND")
	)
	(segment
		(start 373.317516 -287.288986)
		(end 373.317262 -287.28924)
		(width 0.254)
		(layer "F.Cu")
		(net "GND")
	)
	(segment
		(start 441.028582 -222.816674)
		(end 442.133482 -222.816674)
		(width 0.381)
		(layer "F.Cu")
		(net "GND")
	)
	(segment
		(start 88.145366 -239.0394)
		(end 88.145366 -239.57534)
		(width 0.254)
		(layer "F.Cu")
		(net "GND")
	)
	(segment
		(start 371.32768 -240.388902)
		(end 371.32768 -239.853216)
		(width 0.2032)
		(layer "F.Cu")
		(net "GND")
	)
	(segment
		(start 435.823614 -210.916774)
		(end 436.928514 -210.916774)
		(width 0.381)
		(layer "F.Cu")
		(net "GND")
	)
	(segment
		(start 110.230666 -241.48161)
		(end 110.23092 -241.481356)
		(width 0.254)
		(layer "F.Cu")
		(net "GND")
	)
	(segment
		(start 459.559914 -240.666778)
		(end 458.455014 -240.666778)
		(width 0.381)
		(layer "F.Cu")
		(net "GND")
	)
	(segment
		(start 54.42458 -162.397948)
		(end 54.70398 -162.118548)
		(width 0.2032)
		(layer "F.Cu")
		(net "GND")
	)
	(segment
		(start 392.034776 -50.249836)
		(end 390.464548 -50.249836)
		(width 0.254)
		(layer "F.Cu")
		(net "GND")
	)
	(segment
		(start 263.624314 -248.31675)
		(end 264.729214 -248.31675)
		(width 0.381)
		(layer "F.Cu")
		(net "GND")
	)
	(segment
		(start 428.279814 -204.96657)
		(end 429.384714 -204.96657)
		(width 0.381)
		(layer "F.Cu")
		(net "GND")
	)
	(segment
		(start 373.677434 -229.808532)
		(end 373.677434 -229.272846)
		(width 0.2032)
		(layer "F.Cu")
		(net "GND")
	)
	(segment
		(start 286.255714 -210.916774)
		(end 287.360614 -210.916774)
		(width 0.381)
		(layer "F.Cu")
		(net "GND")
	)
	(segment
		(start 34.871914 -196.466714)
		(end 35.976814 -196.466714)
		(width 0.381)
		(layer "F.Cu")
		(net "GND")
	)
	(segment
		(start 261.285482 -312.91657)
		(end 260.180582 -312.91657)
		(width 0.381)
		(layer "F.Cu")
		(net "GND")
	)
	(segment
		(start 100.942648 -275.35886)
		(end 100.942648 -275.8948)
		(width 0.254)
		(layer "F.Cu")
		(net "GND")
	)
	(segment
		(start 97.073466 -214.344758)
		(end 97.073466 -213.732618)
		(width 0.254)
		(layer "F.Cu")
		(net "GND")
	)
	(segment
		(start 48.854614 -204.116686)
		(end 49.959514 -204.116686)
		(width 0.381)
		(layer "F.Cu")
		(net "GND")
	)
	(segment
		(start 382.642364 -345.121484)
		(end 383.02184 -344.742008)
		(width 0.2032)
		(layer "F.Cu")
		(net "GND")
	)
	(segment
		(start 53.403246 -201.56678)
		(end 52.298346 -201.56678)
		(width 0.381)
		(layer "F.Cu")
		(net "GND")
	)
	(segment
		(start 117.388894 -281.05608)
		(end 117.388894 -281.591766)
		(width 0.254)
		(layer "F.Cu")
		(net "GND")
	)
	(segment
		(start 153.60015 -68.962778)
		(end 153.60015 -69.86397)
		(width 0.3556)
		(layer "F.Cu")
		(net "GND")
	)
	(segment
		(start 384.015234 -249.342148)
		(end 383.550922 -249.073924)
		(width 0.254)
		(layer "F.Cu")
		(net "GND")
	)
	(segment
		(start 48.854614 -233.86669)
		(end 49.959514 -233.86669)
		(width 0.381)
		(layer "F.Cu")
		(net "GND")
	)
	(segment
		(start 136.184894 -268.033754)
		(end 136.184894 -268.569694)
		(width 0.254)
		(layer "F.Cu")
		(net "GND")
	)
	(segment
		(start 30.771846 -208.366614)
		(end 31.876746 -208.366614)
		(width 0.381)
		(layer "F.Cu")
		(net "GND")
	)
	(segment
		(start 23.228046 -279.766776)
		(end 24.332946 -279.766776)
		(width 0.381)
		(layer "F.Cu")
		(net "GND")
	)
	(segment
		(start 181.355746 -110.575344)
		(end 181.755796 -110.175294)
		(width 0.3556)
		(layer "F.Cu")
		(net "GND")
	)
	(segment
		(start 44.754546 -216.016586)
		(end 45.859446 -216.016586)
		(width 0.381)
		(layer "F.Cu")
		(net "GND")
	)
	(segment
		(start 95.663512 -226.553268)
		(end 95.663512 -226.017582)
		(width 0.254)
		(layer "F.Cu")
		(net "GND")
	)
	(segment
		(start 27.328114 -222.816674)
		(end 28.433014 -222.816674)
		(width 0.381)
		(layer "F.Cu")
		(net "GND")
	)
	(segment
		(start 367.09858 -216.250774)
		(end 367.098834 -216.25052)
		(width 0.254)
		(layer "F.Cu")
		(net "GND")
	)
	(segment
		(start 343.549478 -41.871392)
		(end 343.821258 -42.341292)
		(width 0.254)
		(layer "F.Cu")
		(net "GND")
	)
	(segment
		(start 380.835916 -283.497782)
		(end 380.835916 -284.033468)
		(width 0.254)
		(layer "F.Cu")
		(net "GND")
	)
	(segment
		(start 336.665316 -272.103342)
		(end 336.665316 -272.639282)
		(width 0.2032)
		(layer "F.Cu")
		(net "GND")
	)
	(segment
		(start 414.297114 -234.716574)
		(end 415.708084 -234.716574)
		(width 0.381)
		(layer "F.Cu")
		(net "GND")
	)
	(segment
		(start 8.140446 -270.416782)
		(end 9.245346 -270.416782)
		(width 0.381)
		(layer "F.Cu")
		(net "GND")
	)
	(segment
		(start 339.84438 -223.297496)
		(end 339.84438 -222.76181)
		(width 0.254)
		(layer "F.Cu")
		(net "GND")
	)
	(segment
		(start 350.38411 -358.452674)
		(end 349.77324 -358.452674)
		(width 0.381)
		(layer "F.Cu")
		(net "GND")
	)
	(segment
		(start 159.918146 -261.916672)
		(end 158.813246 -261.916672)
		(width 0.381)
		(layer "F.Cu")
		(net "GND")
	)
	(segment
		(start 9.277096 -100.417884)
		(end 9.963404 -100.417884)
		(width 0.3556)
		(layer "F.Cu")
		(net "GND")
	)
	(segment
		(start 297.899582 -303.566576)
		(end 299.004482 -303.566576)
		(width 0.381)
		(layer "F.Cu")
		(net "GND")
	)
	(segment
		(start 89.664794 -279.150064)
		(end 89.664794 -279.150318)
		(width 0.2032)
		(layer "F.Cu")
		(net "GND")
	)
	(segment
		(start 293.799514 -267.016738)
		(end 292.694614 -267.016738)
		(width 0.381)
		(layer "F.Cu")
		(net "GND")
	)
	(segment
		(start 20.889214 -207.51673)
		(end 19.784314 -207.51673)
		(width 0.381)
		(layer "F.Cu")
		(net "GND")
	)
	(segment
		(start 23.228046 -311.216802)
		(end 24.332946 -311.216802)
		(width 0.381)
		(layer "F.Cu")
		(net "GND")
	)
	(segment
		(start 370.967762 -279.428194)
		(end 370.967762 -279.96388)
		(width 0.254)
		(layer "F.Cu")
		(net "GND")
	)
	(segment
		(start 421.840914 -304.416714)
		(end 420.736014 -304.416714)
		(width 0.381)
		(layer "F.Cu")
		(net "GND")
	)
	(segment
		(start 449.677282 -277.216616)
		(end 448.572382 -277.216616)
		(width 0.381)
		(layer "F.Cu")
		(net "GND")
	)
	(segment
		(start 433.484782 -238.116618)
		(end 434.589682 -238.116618)
		(width 0.381)
		(layer "F.Cu")
		(net "GND")
	)
	(segment
		(start 130.436112 -247.714262)
		(end 130.436366 -247.714008)
		(width 0.2032)
		(layer "F.Cu")
		(net "GND")
	)
	(segment
		(start 410.853382 -280.61666)
		(end 411.958282 -280.61666)
		(width 0.381)
		(layer "F.Cu")
		(net "GND")
	)
	(segment
		(start 311.882282 -301.01667)
		(end 312.987182 -301.01667)
		(width 0.381)
		(layer "F.Cu")
		(net "GND")
	)
	(segment
		(start 254.975614 -287.416748)
		(end 256.080514 -287.416748)
		(width 0.381)
		(layer "F.Cu")
		(net "GND")
	)
	(segment
		(start 349.456756 -338.493862)
		(end 349.329248 -338.366354)
		(width 0.381)
		(layer "F.Cu")
		(net "GND")
	)
	(segment
		(start 118.328694 -284.847284)
		(end 118.328948 -284.847538)
		(width 0.254)
		(layer "F.Cu")
		(net "GND")
	)
	(segment
		(start 275.268182 -278.916638)
		(end 274.163282 -278.916638)
		(width 0.381)
		(layer "F.Cu")
		(net "GND")
	)
	(segment
		(start 150.15083 -124.005848)
		(end 150.76043 -124.005848)
		(width 0.3556)
		(layer "F.Cu")
		(net "GND")
	)
	(segment
		(start 110.485682 -338.698078)
		(end 110.485682 -339.324696)
		(width 0.381)
		(layer "F.Cu")
		(net "GND")
	)
	(segment
		(start 428.279814 -306.116736)
		(end 429.384714 -306.116736)
		(width 0.381)
		(layer "F.Cu")
		(net "GND")
	)
	(segment
		(start 453.121014 -285.716726)
		(end 452.016114 -285.716726)
		(width 0.381)
		(layer "F.Cu")
		(net "GND")
	)
	(segment
		(start 290.355782 -297.616626)
		(end 291.460682 -297.616626)
		(width 0.381)
		(layer "F.Cu")
		(net "GND")
	)
	(segment
		(start 115.869466 -230.622602)
		(end 115.869212 -230.622348)
		(width 0.254)
		(layer "F.Cu")
		(net "GND")
	)
	(segment
		(start 100.472494 -270.197326)
		(end 100.472748 -270.19758)
		(width 0.2032)
		(layer "F.Cu")
		(net "GND")
	)
	(segment
		(start 370.498116 -280.242264)
		(end 370.497862 -280.778204)
		(width 0.254)
		(layer "F.Cu")
		(net "GND")
	)
	(segment
		(start 335.255362 -279.428194)
		(end 335.255362 -279.964134)
		(width 0.2032)
		(layer "F.Cu")
		(net "GND")
	)
	(segment
		(start 343.13368 -230.622348)
		(end 343.13368 -230.086662)
		(width 0.2032)
		(layer "F.Cu")
		(net "GND")
	)
	(segment
		(start 95.139256 -98.927412)
		(end 95.036386 -98.927412)
		(width 0.3556)
		(layer "F.Cu")
		(net "GND")
	)
	(segment
		(start 418.397182 -211.766658)
		(end 417.292282 -211.766658)
		(width 0.381)
		(layer "F.Cu")
		(net "GND")
	)
	(segment
		(start 188.988446 -276.366732)
		(end 190.093346 -276.366732)
		(width 0.381)
		(layer "F.Cu")
		(net "GND")
	)
	(segment
		(start 7.035546 -246.616728)
		(end 8.140446 -246.616728)
		(width 0.381)
		(layer "F.Cu")
		(net "GND")
	)
	(segment
		(start 443.083188 -38.487858)
		(end 442.270388 -38.487858)
		(width 0.3556)
		(layer "F.Cu")
		(net "GND")
	)
	(segment
		(start 18.679414 -272.966688)
		(end 19.784314 -272.966688)
		(width 0.381)
		(layer "F.Cu")
		(net "GND")
	)
	(segment
		(start 127.616712 -231.436418)
		(end 127.616966 -231.436164)
		(width 0.2032)
		(layer "F.Cu")
		(net "GND")
	)
	(segment
		(start 441.028582 -250.866656)
		(end 442.133482 -250.866656)
		(width 0.381)
		(layer "F.Cu")
		(net "GND")
	)
	(segment
		(start 337.02498 -247.178576)
		(end 337.025234 -247.178322)
		(width 0.2032)
		(layer "F.Cu")
		(net "GND")
	)
	(segment
		(start 370.498116 -266.127992)
		(end 370.497862 -266.128246)
		(width 0.254)
		(layer "F.Cu")
		(net "GND")
	)
	(segment
		(start 272.059654 -92.870274)
		(end 271.03578 -92.870274)
		(width 0.3556)
		(layer "F.Cu")
		(net "GND")
	)
	(segment
		(start 180.339746 -309.51678)
		(end 181.444646 -309.51678)
		(width 0.381)
		(layer "F.Cu")
		(net "GND")
	)
	(segment
		(start 23.228046 -240.666778)
		(end 24.332946 -240.666778)
		(width 0.381)
		(layer "F.Cu")
		(net "GND")
	)
	(segment
		(start 165.077902 -311.216802)
		(end 166.357046 -311.216802)
		(width 0.381)
		(layer "F.Cu")
		(net "GND")
	)
	(segment
		(start 361.460034 -220.041724)
		(end 361.460034 -219.506038)
		(width 0.254)
		(layer "F.Cu")
		(net "GND")
	)
	(segment
		(start 90.604848 -267.219938)
		(end 90.604848 -267.755878)
		(width 0.2032)
		(layer "F.Cu")
		(net "GND")
	)
	(segment
		(start 12.240514 -301.01667)
		(end 13.345414 -301.01667)
		(width 0.381)
		(layer "F.Cu")
		(net "GND")
	)
	(segment
		(start 361.45978 -242.830858)
		(end 361.45978 -242.295172)
		(width 0.254)
		(layer "F.Cu")
		(net "GND")
	)
	(segment
		(start 16.789146 -221.96679)
		(end 15.684246 -221.96679)
		(width 0.381)
		(layer "F.Cu")
		(net "GND")
	)
	(segment
		(start 383.185162 -275.08073)
		(end 383.185416 -275.080984)
		(width 0.2032)
		(layer "F.Cu")
		(net "GND")
	)
	(segment
		(start 382.245362 -255.011682)
		(end 382.245362 -255.547368)
		(width 0.2032)
		(layer "F.Cu")
		(net "GND")
	)
	(segment
		(start 165.252146 -238.966756)
		(end 166.357046 -238.966756)
		(width 0.381)
		(layer "F.Cu")
		(net "GND")
	)
	(segment
		(start 164.99205 -23.713948)
		(end 164.99205 -24.263858)
		(width 0.3556)
		(layer "F.Cu")
		(net "GND")
	)
	(segment
		(start 364.389162 -283.219652)
		(end 364.389416 -283.219906)
		(width 0.254)
		(layer "F.Cu")
		(net "GND")
	)
	(segment
		(start 305.443382 -288.266632)
		(end 306.764182 -288.266632)
		(width 0.381)
		(layer "F.Cu")
		(net "GND")
	)
	(segment
		(start 161.478976 -288.266632)
		(end 162.913314 -288.266632)
		(width 0.381)
		(layer "F.Cu")
		(net "GND")
	)
	(segment
		(start 188.988446 -290.816792)
		(end 187.883546 -290.816792)
		(width 0.381)
		(layer "F.Cu")
		(net "GND")
	)
	(segment
		(start 262.519414 -220.266768)
		(end 263.624314 -220.266768)
		(width 0.381)
		(layer "F.Cu")
		(net "GND")
	)
	(segment
		(start 361.45978 -247.714262)
		(end 361.45978 -247.178576)
		(width 0.254)
		(layer "F.Cu")
		(net "GND")
	)
	(segment
		(start 128.196848 -257.45313)
		(end 128.196594 -257.98907)
		(width 0.2032)
		(layer "F.Cu")
		(net "GND")
	)
	(segment
		(start 37.969444 -126.69774)
		(end 37.356288 -126.69774)
		(width 0.381)
		(layer "F.Cu")
		(net "GND")
	)
	(segment
		(start 296.794682 -200.716642)
		(end 297.899582 -200.716642)
		(width 0.381)
		(layer "F.Cu")
		(net "GND")
	)
	(segment
		(start 290.355782 -308.666642)
		(end 291.460682 -308.666642)
		(width 0.381)
		(layer "F.Cu")
		(net "GND")
	)
	(segment
		(start 348.77248 -228.994716)
		(end 348.77248 -228.45903)
		(width 0.2032)
		(layer "F.Cu")
		(net "GND")
	)
	(segment
		(start 285.150814 -216.016586)
		(end 286.255714 -216.016586)
		(width 0.381)
		(layer "F.Cu")
		(net "GND")
	)
	(segment
		(start 131.485894 -281.591512)
		(end 131.486148 -281.591766)
		(width 0.254)
		(layer "F.Cu")
		(net "GND")
	)
	(segment
		(start 277.607014 -216.016586)
		(end 278.711914 -216.016586)
		(width 0.381)
		(layer "F.Cu")
		(net "GND")
	)
	(segment
		(start 256.080514 -203.266802)
		(end 257.185414 -203.266802)
		(width 0.381)
		(layer "F.Cu")
		(net "GND")
	)
	(segment
		(start 38.315646 -285.716726)
		(end 37.210746 -285.716726)
		(width 0.381)
		(layer "F.Cu")
		(net "GND")
	)
	(segment
		(start 362.979462 -264.500106)
		(end 362.979462 -264.50036)
		(width 0.254)
		(layer "F.Cu")
		(net "GND")
	)
	(segment
		(start 464.764882 -286.56661)
		(end 463.659982 -286.56661)
		(width 0.381)
		(layer "F.Cu")
		(net "GND")
	)
	(segment
		(start 101.302312 -226.553268)
		(end 101.302312 -226.017582)
		(width 0.254)
		(layer "F.Cu")
		(net "GND")
	)
	(segment
		(start 199.527414 -196.466714)
		(end 200.632314 -196.466714)
		(width 0.381)
		(layer "F.Cu")
		(net "GND")
	)
	(segment
		(start 42.415714 -239.81664)
		(end 41.310814 -239.81664)
		(width 0.381)
		(layer "F.Cu")
		(net "GND")
	)
	(segment
		(start 296.794682 -306.96662)
		(end 297.899582 -306.96662)
		(width 0.381)
		(layer "F.Cu")
		(net "GND")
	)
	(segment
		(start 14.579346 -250.016772)
		(end 15.684246 -250.016772)
		(width 0.381)
		(layer "F.Cu")
		(net "GND")
	)
	(segment
		(start 457.221082 -238.116618)
		(end 456.116182 -238.116618)
		(width 0.381)
		(layer "F.Cu")
		(net "GND")
	)
	(segment
		(start 138.894312 -244.458744)
		(end 139.628626 -244.458744)
		(width 0.254)
		(layer "F.Cu")
		(net "GND")
	)
	(segment
		(start 325.480172 -345.53398)
		(end 325.6534 -345.115896)
		(width 0.1778)
		(layer "F.Cu")
		(net "GND")
	)
	(segment
		(start 200.632314 -196.466714)
		(end 201.737214 -196.466714)
		(width 0.381)
		(layer "F.Cu")
		(net "GND")
	)
	(segment
		(start 378.956316 -259.093462)
		(end 378.956062 -259.616956)
		(width 0.2032)
		(layer "F.Cu")
		(net "GND")
	)
	(segment
		(start 285.150814 -260.21665)
		(end 286.255714 -260.21665)
		(width 0.381)
		(layer "F.Cu")
		(net "GND")
	)
	(segment
		(start 306.0192 -27.6606)
		(end 306.0192 -26.5684)
		(width 0.3556)
		(layer "F.Cu")
		(net "GND")
	)
	(segment
		(start 380.256034 -229.808532)
		(end 380.256034 -229.272846)
		(width 0.2032)
		(layer "F.Cu")
		(net "GND")
	)
	(segment
		(start 451.81647 -111.291624)
		(end 451.658228 -111.133382)
		(width 0.3556)
		(layer "F.Cu")
		(net "GND")
	)
	(segment
		(start 87.785194 -275.35886)
		(end 87.31504 -275.080984)
		(width 0.254)
		(layer "F.Cu")
		(net "GND")
	)
	(segment
		(start 281.707082 -219.41663)
		(end 282.811982 -219.41663)
		(width 0.381)
		(layer "F.Cu")
		(net "GND")
	)
	(segment
		(start 345.013534 -214.344758)
		(end 345.013534 -213.732618)
		(width 0.254)
		(layer "F.Cu")
		(net "GND")
	)
	(segment
		(start 370.967762 -261.522718)
		(end 370.967762 -262.058658)
		(width 0.2032)
		(layer "F.Cu")
		(net "GND")
	)
	(segment
		(start 183.353964 -334.467962)
		(end 183.353964 -335.483962)
		(width 0.508)
		(layer "F.Cu")
		(net "GND")
	)
	(segment
		(start 43.520614 -269.566644)
		(end 42.415714 -269.566644)
		(width 0.381)
		(layer "F.Cu")
		(net "GND")
	)
	(segment
		(start 134.14883 -103.81107)
		(end 134.409942 -104.072182)
		(width 0.254)
		(layer "F.Cu")
		(net "GND")
	)
	(segment
		(start 214.615014 -205.816708)
		(end 215.719914 -205.816708)
		(width 0.381)
		(layer "F.Cu")
		(net "GND")
	)
	(segment
		(start 169.352214 -277.216616)
		(end 170.457114 -277.216616)
		(width 0.381)
		(layer "F.Cu")
		(net "GND")
	)
	(segment
		(start 94.723712 -239.57534)
		(end 94.723712 -239.0394)
		(width 0.2032)
		(layer "F.Cu")
		(net "GND")
	)
	(segment
		(start 91.544648 -278.614378)
		(end 91.544394 -279.150318)
		(width 0.2032)
		(layer "F.Cu")
		(net "GND")
	)
	(segment
		(start 133.365494 -282.683966)
		(end 133.365748 -282.68422)
		(width 0.254)
		(layer "F.Cu")
		(net "GND")
	)
	(segment
		(start 457.221082 -196.466714)
		(end 456.116182 -196.466714)
		(width 0.381)
		(layer "F.Cu")
		(net "GND")
	)
	(segment
		(start 382.135634 -233.064304)
		(end 382.135634 -232.528364)
		(width 0.2032)
		(layer "F.Cu")
		(net "GND")
	)
	(segment
		(start 275.268182 -204.116686)
		(end 274.163282 -204.116686)
		(width 0.381)
		(layer "F.Cu")
		(net "GND")
	)
	(segment
		(start 210.514946 -267.016738)
		(end 211.619846 -267.016738)
		(width 0.381)
		(layer "F.Cu")
		(net "GND")
	)
	(segment
		(start 94.833694 -276.172676)
		(end 94.833694 -276.708362)
		(width 0.2032)
		(layer "F.Cu")
		(net "GND")
	)
	(segment
		(start 343.403174 -39.443152)
		(end 343.903046 -39.295324)
		(width 0.2032)
		(layer "F.Cu")
		(net "GND")
	)
	(segment
		(start 444.472314 -214.316564)
		(end 445.577214 -214.316564)
		(width 0.381)
		(layer "F.Cu")
		(net "GND")
	)
	(segment
		(start 30.771846 -244.916706)
		(end 31.876746 -244.916706)
		(width 0.381)
		(layer "F.Cu")
		(net "GND")
	)
	(segment
		(start 136.176258 -63.744348)
		(end 136.176258 -62.903608)
		(width 0.3556)
		(layer "F.Cu")
		(net "GND")
	)
	(segment
		(start 288.545016 -367.755932)
		(end 288.545016 -367.792508)
		(width 0.381)
		(layer "F.Cu")
		(net "GND")
	)
	(segment
		(start 177.9524 -94.738698)
		(end 177.9524 -95.367348)
		(width 0.3556)
		(layer "F.Cu")
		(net "GND")
	)
	(segment
		(start 347.214698 -38.945566)
		(end 347.214698 -39.03091)
		(width 0.2032)
		(layer "F.Cu")
		(net "GND")
	)
	(segment
		(start 335.725262 -273.730974)
		(end 335.725262 -274.266914)
		(width 0.2032)
		(layer "F.Cu")
		(net "GND")
	)
	(segment
		(start 382.245362 -285.939484)
		(end 382.245362 -286.47517)
		(width 0.2032)
		(layer "F.Cu")
		(net "GND")
	)
	(segment
		(start 12.022582 -421.616886)
		(end 11.387582 -421.616886)
		(width 0.3556)
		(layer "F.Cu")
		(net "GND")
	)
	(segment
		(start 351.12198 -222.76181)
		(end 351.122234 -222.761556)
		(width 0.254)
		(layer "F.Cu")
		(net "GND")
	)
	(segment
		(start 175.005746 -212.616796)
		(end 173.900846 -212.616796)
		(width 0.381)
		(layer "F.Cu")
		(net "GND")
	)
	(segment
		(start 200.632314 -210.066636)
		(end 201.737214 -210.066636)
		(width 0.381)
		(layer "F.Cu")
		(net "GND")
	)
	(segment
		(start 333.117444 -278.711406)
		(end 333.214472 -278.614378)
		(width 0.2032)
		(layer "F.Cu")
		(net "GND")
	)
	(segment
		(start 97.653094 -257.175254)
		(end 97.653094 -256.639314)
		(width 0.2032)
		(layer "F.Cu")
		(net "GND")
	)
	(segment
		(start 100.362766 -237.947454)
		(end 100.362766 -237.411514)
		(width 0.254)
		(layer "F.Cu")
		(net "GND")
	)
	(segment
		(start 426.697902 -124.91466)
		(end 426.075856 -124.91466)
		(width 0.381)
		(layer "F.Cu")
		(net "GND")
	)
	(segment
		(start 272.273014 -203.266802)
		(end 271.168114 -203.266802)
		(width 0.381)
		(layer "F.Cu")
		(net "GND")
	)
	(segment
		(start 176.478438 -417.745418)
		(end 177.088038 -417.745418)
		(width 0.381)
		(layer "F.Cu")
		(net "GND")
	)
	(segment
		(start 290.355782 -230.466646)
		(end 291.460682 -230.466646)
		(width 0.381)
		(layer "F.Cu")
		(net "GND")
	)
	(segment
		(start 207.071214 -249.166634)
		(end 208.176114 -249.166634)
		(width 0.381)
		(layer "F.Cu")
		(net "GND")
	)
	(segment
		(start 181.444646 -290.816792)
		(end 180.339746 -290.816792)
		(width 0.381)
		(layer "F.Cu")
		(net "GND")
	)
	(segment
		(start 162.913314 -271.266666)
		(end 164.018214 -271.266666)
		(width 0.381)
		(layer "F.Cu")
		(net "GND")
	)
	(segment
		(start 200.632314 -272.966688)
		(end 201.737214 -272.966688)
		(width 0.381)
		(layer "F.Cu")
		(net "GND")
	)
	(segment
		(start 380.25578 -229.808786)
		(end 380.256034 -229.808532)
		(width 0.2032)
		(layer "F.Cu")
		(net "GND")
	)
	(segment
		(start 403.846792 -8.320024)
		(end 403.846792 -9.424924)
		(width 0.3556)
		(layer "F.Cu")
		(net "GND")
	)
	(segment
		(start 375.666762 -261.522718)
		(end 375.666762 -262.058404)
		(width 0.254)
		(layer "F.Cu")
		(net "GND")
	)
	(segment
		(start 436.928514 -240.666778)
		(end 438.033414 -240.666778)
		(width 0.381)
		(layer "F.Cu")
		(net "GND")
	)
	(segment
		(start 130.906266 -235.506006)
		(end 130.906012 -235.505752)
		(width 0.2032)
		(layer "F.Cu")
		(net "GND")
	)
	(segment
		(start 39.420546 -223.666558)
		(end 38.315646 -223.666558)
		(width 0.381)
		(layer "F.Cu")
		(net "GND")
	)
	(segment
		(start 52.894738 -334.537304)
		(end 52.894738 -335.477612)
		(width 0.508)
		(layer "F.Cu")
		(net "GND")
	)
	(segment
		(start 377.076716 -260.708902)
		(end 377.076716 -261.244588)
		(width 0.2032)
		(layer "F.Cu")
		(net "GND")
	)
	(segment
		(start 166.357046 -317.166752)
		(end 165.252146 -317.166752)
		(width 0.381)
		(layer "F.Cu")
		(net "GND")
	)
	(segment
		(start 94.253812 -228.994716)
		(end 94.253812 -228.45903)
		(width 0.2032)
		(layer "F.Cu")
		(net "GND")
	)
	(segment
		(start 48.854614 -213.46668)
		(end 49.959514 -213.46668)
		(width 0.381)
		(layer "F.Cu")
		(net "GND")
	)
	(segment
		(start 211.619846 -298.466764)
		(end 210.514946 -298.466764)
		(width 0.381)
		(layer "F.Cu")
		(net "GND")
	)
	(segment
		(start 60.947046 -236.416596)
		(end 62.267846 -236.416596)
		(width 0.381)
		(layer "F.Cu")
		(net "GND")
	)
	(segment
		(start 190.093346 -206.666592)
		(end 188.988446 -206.666592)
		(width 0.381)
		(layer "F.Cu")
		(net "GND")
	)
	(segment
		(start 38.315646 -204.96657)
		(end 37.210746 -204.96657)
		(width 0.381)
		(layer "F.Cu")
		(net "GND")
	)
	(segment
		(start 407.892504 -295.06672)
		(end 406.753314 -295.06672)
		(width 0.381)
		(layer "F.Cu")
		(net "GND")
	)
	(segment
		(start 324.793864 -26.579322)
		(end 324.793864 -26.143712)
		(width 0.3556)
		(layer "F.Cu")
		(net "GND")
	)
	(segment
		(start 181.444646 -278.066754)
		(end 182.549546 -278.066754)
		(width 0.381)
		(layer "F.Cu")
		(net "GND")
	)
	(segment
		(start 214.615014 -289.966654)
		(end 215.719914 -289.966654)
		(width 0.381)
		(layer "F.Cu")
		(net "GND")
	)
	(segment
		(start 435.823614 -212.616796)
		(end 436.928514 -212.616796)
		(width 0.381)
		(layer "F.Cu")
		(net "GND")
	)
	(segment
		(start 347.363034 -244.45849)
		(end 347.363034 -243.922804)
		(width 0.2032)
		(layer "F.Cu")
		(net "GND")
	)
	(segment
		(start 107.521248 -282.405582)
		(end 107.520994 -282.405836)
		(width 0.254)
		(layer "F.Cu")
		(net "GND")
	)
	(segment
		(start 382.715516 -257.988816)
		(end 382.715262 -257.98907)
		(width 0.2032)
		(layer "F.Cu")
		(net "GND")
	)
	(segment
		(start 56.398414 -215.166702)
		(end 57.503314 -215.166702)
		(width 0.381)
		(layer "F.Cu")
		(net "GND")
	)
	(segment
		(start 18.679414 -250.866656)
		(end 19.784314 -250.866656)
		(width 0.381)
		(layer "F.Cu")
		(net "GND")
	)
	(segment
		(start 311.882282 -258.516628)
		(end 312.987182 -258.516628)
		(width 0.381)
		(layer "F.Cu")
		(net "GND")
	)
	(segment
		(start 286.043878 -364.60049)
		(end 286.386016 -364.60049)
		(width 0.2032)
		(layer "F.Cu")
		(net "GND")
	)
	(segment
		(start 210.514946 -246.616728)
		(end 211.619846 -246.616728)
		(width 0.381)
		(layer "F.Cu")
		(net "GND")
	)
	(segment
		(start 200.632314 -278.916638)
		(end 201.737214 -278.916638)
		(width 0.381)
		(layer "F.Cu")
		(net "GND")
	)
	(segment
		(start 369.91798 -223.297496)
		(end 369.91798 -222.76181)
		(width 0.254)
		(layer "F.Cu")
		(net "GND")
	)
	(segment
		(start 337.96478 -223.297496)
		(end 337.96478 -222.76181)
		(width 0.254)
		(layer "F.Cu")
		(net "GND")
	)
	(segment
		(start 102.712266 -217.600276)
		(end 102.712266 -217.064336)
		(width 0.2032)
		(layer "F.Cu")
		(net "GND")
	)
	(segment
		(start 336.373216 -342.106758)
		(end 336.20964 -342.270334)
		(width 0.381)
		(layer "F.Cu")
		(net "GND")
	)
	(segment
		(start 411.958282 -211.766658)
		(end 410.853382 -211.766658)
		(width 0.381)
		(layer "F.Cu")
		(net "GND")
	)
	(segment
		(start 301.343314 -304.416714)
		(end 302.448214 -304.416714)
		(width 0.381)
		(layer "F.Cu")
		(net "GND")
	)
	(segment
		(start 214.615014 -244.066568)
		(end 215.719914 -244.066568)
		(width 0.381)
		(layer "F.Cu")
		(net "GND")
	)
	(segment
		(start 113.629694 -259.894832)
		(end 113.629694 -260.430772)
		(width 0.254)
		(layer "F.Cu")
		(net "GND")
	)
	(segment
		(start 297.899582 -238.116618)
		(end 299.004482 -238.116618)
		(width 0.381)
		(layer "F.Cu")
		(net "GND")
	)
	(segment
		(start 39.420546 -258.516628)
		(end 38.315646 -258.516628)
		(width 0.381)
		(layer "F.Cu")
		(net "GND")
	)
	(segment
		(start 53.842666 -117.40769)
		(end 53.233066 -117.40769)
		(width 0.381)
		(layer "F.Cu")
		(net "GND")
	)
	(segment
		(start 275.268182 -266.1666)
		(end 274.163282 -266.1666)
		(width 0.381)
		(layer "F.Cu")
		(net "GND")
	)
	(segment
		(start 443.367414 -233.016806)
		(end 444.472314 -233.016806)
		(width 0.381)
		(layer "F.Cu")
		(net "GND")
	)
	(segment
		(start 305.443382 -272.966688)
		(end 306.764182 -272.966688)
		(width 0.381)
		(layer "F.Cu")
		(net "GND")
	)
	(segment
		(start 138.424666 -219.228162)
		(end 138.424666 -218.692222)
		(width 0.254)
		(layer "F.Cu")
		(net "GND")
	)
	(segment
		(start 338.904834 -244.45849)
		(end 338.904834 -243.922804)
		(width 0.2032)
		(layer "F.Cu")
		(net "GND")
	)
	(segment
		(start 126.317248 -263.96442)
		(end 126.317248 -264.50036)
		(width 0.2032)
		(layer "F.Cu")
		(net "GND")
	)
	(segment
		(start 186.649614 -288.266632)
		(end 185.544714 -288.266632)
		(width 0.381)
		(layer "F.Cu")
		(net "GND")
	)
	(segment
		(start 263.624314 -199.01662)
		(end 264.729214 -199.01662)
		(width 0.381)
		(layer "F.Cu")
		(net "GND")
	)
	(segment
		(start 347.003116 -283.497782)
		(end 347.003116 -284.033468)
		(width 0.254)
		(layer "F.Cu")
		(net "GND")
	)
	(segment
		(start 11.135614 -204.116686)
		(end 12.240514 -204.116686)
		(width 0.381)
		(layer "F.Cu")
		(net "GND")
	)
	(segment
		(start 127.147066 -227.367084)
		(end 127.147066 -226.831144)
		(width 0.2032)
		(layer "F.Cu")
		(net "GND")
	)
	(segment
		(start 89.555066 -250.155964)
		(end 89.554812 -250.15571)
		(width 0.2032)
		(layer "F.Cu")
		(net "GND")
	)
	(segment
		(start 384.595116 -276.986492)
		(end 384.595116 -277.522178)
		(width 0.254)
		(layer "F.Cu")
		(net "GND")
	)
	(segment
		(start 307.782214 -278.066754)
		(end 308.887114 -278.066754)
		(width 0.381)
		(layer "F.Cu")
		(net "GND")
	)
	(segment
		(start 201.592942 -131.100068)
		(end 201.592942 -130.266948)
		(width 0.3556)
		(layer "F.Cu")
		(net "GND")
	)
	(segment
		(start 383.655062 -281.869896)
		(end 383.655062 -282.405836)
		(width 0.254)
		(layer "F.Cu")
		(net "GND")
	)
	(segment
		(start 251.139706 -47.078138)
		(end 250.113546 -47.078138)
		(width 0.3556)
		(layer "F.Cu")
		(net "GND")
	)
	(segment
		(start 49.959514 -282.316682)
		(end 51.064414 -282.316682)
		(width 0.381)
		(layer "F.Cu")
		(net "GND")
	)
	(segment
		(start 114.459766 -223.297496)
		(end 114.459766 -222.761556)
		(width 0.254)
		(layer "F.Cu")
		(net "GND")
	)
	(segment
		(start 305.443382 -224.516696)
		(end 306.548282 -224.516696)
		(width 0.381)
		(layer "F.Cu")
		(net "GND")
	)
	(segment
		(start 130.906266 -237.133892)
		(end 130.906012 -237.133638)
		(width 0.254)
		(layer "F.Cu")
		(net "GND")
	)
	(segment
		(start 266.619482 -262.76681)
		(end 267.724382 -262.76681)
		(width 0.381)
		(layer "F.Cu")
		(net "GND")
	)
	(segment
		(start 463.659982 -291.666676)
		(end 462.555082 -291.666676)
		(width 0.381)
		(layer "F.Cu")
		(net "GND")
	)
	(segment
		(start 345.15171 -46.350936)
		(end 345.554554 -46.949614)
		(width 0.1778)
		(layer "F.Cu")
		(net "GND")
	)
	(segment
		(start 443.367414 -227.066602)
		(end 444.472314 -227.066602)
		(width 0.381)
		(layer "F.Cu")
		(net "GND")
	)
	(segment
		(start 18.679414 -301.01667)
		(end 19.784314 -301.01667)
		(width 0.381)
		(layer "F.Cu")
		(net "GND")
	)
	(segment
		(start 45.859446 -315.46673)
		(end 44.754546 -315.46673)
		(width 0.381)
		(layer "F.Cu")
		(net "GND")
	)
	(segment
		(start 262.519414 -268.71676)
		(end 263.624314 -268.71676)
		(width 0.381)
		(layer "F.Cu")
		(net "GND")
	)
	(segment
		(start 170.457114 -207.51673)
		(end 171.806362 -207.51673)
		(width 0.381)
		(layer "F.Cu")
		(net "GND")
	)
	(segment
		(start 308.33314 -430.33696)
		(end 308.33314 -429.699928)
		(width 0.3556)
		(layer "F.Cu")
		(net "GND")
	)
	(segment
		(start 72.88403 -144.665192)
		(end 72.258428 -144.665192)
		(width 0.3556)
		(layer "F.Cu")
		(net "GND")
	)
	(segment
		(start 165.210998 -126.67996)
		(end 166.0652 -126.67996)
		(width 0.3556)
		(layer "F.Cu")
		(net "GND")
	)
	(segment
		(start 342.304116 -265.592306)
		(end 342.303862 -265.592306)
		(width 0.254)
		(layer "F.Cu")
		(net "GND")
	)
	(segment
		(start 418.397182 -291.666676)
		(end 417.002976 -291.666676)
		(width 0.381)
		(layer "F.Cu")
		(net "GND")
	)
	(segment
		(start 91.434412 -237.133638)
		(end 91.434412 -236.597952)
		(width 0.2032)
		(layer "F.Cu")
		(net "GND")
	)
	(segment
		(start 29.538422 -403.045422)
		(end 29.031692 -403.045422)
		(width 0.3556)
		(layer "F.Cu")
		(net "GND")
	)
	(segment
		(start 137.594594 -267.219938)
		(end 137.594594 -267.755878)
		(width 0.254)
		(layer "F.Cu")
		(net "GND")
	)
	(segment
		(start 199.527414 -314.616592)
		(end 200.632314 -314.616592)
		(width 0.381)
		(layer "F.Cu")
		(net "GND")
	)
	(segment
		(start 285.150814 -300.166786)
		(end 286.255714 -300.166786)
		(width 0.381)
		(layer "F.Cu")
		(net "GND")
	)
	(segment
		(start 212.724746 -309.51678)
		(end 211.619846 -309.51678)
		(width 0.381)
		(layer "F.Cu")
		(net "GND")
	)
	(segment
		(start 355.821234 -220.041724)
		(end 355.821234 -219.506038)
		(width 0.254)
		(layer "F.Cu")
		(net "GND")
	)
	(segment
		(start 377.90628 -240.388902)
		(end 377.90628 -239.853216)
		(width 0.2032)
		(layer "F.Cu")
		(net "GND")
	)
	(segment
		(start 171.783248 -358.534716)
		(end 171.619672 -358.698292)
		(width 0.3556)
		(layer "F.Cu")
		(net "GND")
	)
	(segment
		(start 290.355782 -249.166634)
		(end 291.460682 -249.166634)
		(width 0.381)
		(layer "F.Cu")
		(net "GND")
	)
	(segment
		(start 86.735666 -245.27256)
		(end 87.205566 -245.55069)
		(width 0.254)
		(layer "F.Cu")
		(net "GND")
	)
	(segment
		(start 103.761794 -267.220192)
		(end 103.761794 -267.755878)
		(width 0.254)
		(layer "F.Cu")
		(net "GND")
	)
	(segment
		(start 88.145366 -240.667286)
		(end 88.145366 -241.203226)
		(width 0.254)
		(layer "F.Cu")
		(net "GND")
	)
	(segment
		(start 374.147334 -233.87812)
		(end 374.147334 -233.34218)
		(width 0.2032)
		(layer "F.Cu")
		(net "GND")
	)
	(segment
		(start 63.942214 -264.466578)
		(end 65.047114 -264.466578)
		(width 0.381)
		(layer "F.Cu")
		(net "GND")
	)
	(segment
		(start 276.373082 -238.116618)
		(end 275.268182 -238.116618)
		(width 0.381)
		(layer "F.Cu")
		(net "GND")
	)
	(segment
		(start 375.087134 -227.367084)
		(end 375.087134 -226.831144)
		(width 0.2032)
		(layer "F.Cu")
		(net "GND")
	)
	(segment
		(start 86.260178 -245.540276)
		(end 86.265766 -245.545864)
		(width 0.2032)
		(layer "F.Cu")
		(net "GND")
	)
	(segment
		(start 45.859446 -276.366732)
		(end 46.964346 -276.366732)
		(width 0.381)
		(layer "F.Cu")
		(net "GND")
	)
	(segment
		(start 94.254066 -233.87812)
		(end 94.253812 -233.877866)
		(width 0.2032)
		(layer "F.Cu")
		(net "GND")
	)
	(segment
		(start 262.519414 -248.31675)
		(end 263.624314 -248.31675)
		(width 0.381)
		(layer "F.Cu")
		(net "GND")
	)
	(segment
		(start 370.967762 -263.150604)
		(end 370.967762 -263.686544)
		(width 0.2032)
		(layer "F.Cu")
		(net "GND")
	)
	(segment
		(start 170.457114 -280.61666)
		(end 169.352214 -280.61666)
		(width 0.381)
		(layer "F.Cu")
		(net "GND")
	)
	(segment
		(start 421.840914 -272.116804)
		(end 420.736014 -272.116804)
		(width 0.381)
		(layer "F.Cu")
		(net "GND")
	)
	(segment
		(start 23.228046 -315.46673)
		(end 24.332946 -315.46673)
		(width 0.381)
		(layer "F.Cu")
		(net "GND")
	)
	(segment
		(start 34.871914 -282.316682)
		(end 33.767014 -282.316682)
		(width 0.381)
		(layer "F.Cu")
		(net "GND")
	)
	(segment
		(start 166.357046 -258.516628)
		(end 167.461946 -258.516628)
		(width 0.381)
		(layer "F.Cu")
		(net "GND")
	)
	(segment
		(start 134.305294 -271.289272)
		(end 134.305548 -271.825212)
		(width 0.2032)
		(layer "F.Cu")
		(net "GND")
	)
	(segment
		(start 293.799514 -227.066602)
		(end 292.694614 -227.066602)
		(width 0.381)
		(layer "F.Cu")
		(net "GND")
	)
	(segment
		(start 94.723712 -226.553268)
		(end 94.723712 -226.017582)
		(width 0.254)
		(layer "F.Cu")
		(net "GND")
	)
	(segment
		(start 276.373082 -198.166736)
		(end 275.268182 -198.166736)
		(width 0.381)
		(layer "F.Cu")
		(net "GND")
	)
	(segment
		(start 308.887114 -240.666778)
		(end 309.992014 -240.666778)
		(width 0.381)
		(layer "F.Cu")
		(net "GND")
	)
	(segment
		(start 384.485134 -239.85347)
		(end 384.48488 -239.853216)
		(width 0.254)
		(layer "F.Cu")
		(net "GND")
	)
	(segment
		(start 204.076046 -251.716794)
		(end 205.180946 -251.716794)
		(width 0.381)
		(layer "F.Cu")
		(net "GND")
	)
	(segment
		(start 267.724382 -305.266598)
		(end 268.829282 -305.266598)
		(width 0.381)
		(layer "F.Cu")
		(net "GND")
	)
	(segment
		(start 105.061766 -229.808532)
		(end 105.061766 -229.272846)
		(width 0.2032)
		(layer "F.Cu")
		(net "GND")
	)
	(segment
		(start 378.37618 -222.76181)
		(end 378.376434 -222.761556)
		(width 0.254)
		(layer "F.Cu")
		(net "GND")
	)
	(segment
		(start 110.230666 -246.365014)
		(end 110.23092 -246.36476)
		(width 0.254)
		(layer "F.Cu")
		(net "GND")
	)
	(segment
		(start 27.328114 -235.566712)
		(end 28.433014 -235.566712)
		(width 0.381)
		(layer "F.Cu")
		(net "GND")
	)
	(segment
		(start 187.883546 -315.46673)
		(end 188.988446 -315.46673)
		(width 0.381)
		(layer "F.Cu")
		(net "GND")
	)
	(segment
		(start 204.076046 -199.01662)
		(end 205.180946 -199.01662)
		(width 0.381)
		(layer "F.Cu")
		(net "GND")
	)
	(segment
		(start 150.684992 -40.50792)
		(end 151.42972 -40.50792)
		(width 0.3556)
		(layer "F.Cu")
		(net "GND")
	)
	(segment
		(start 350.762316 -265.592306)
		(end 350.762062 -265.592306)
		(width 0.2032)
		(layer "F.Cu")
		(net "GND")
	)
	(segment
		(start 432.379882 -301.01667)
		(end 433.484782 -301.01667)
		(width 0.381)
		(layer "F.Cu")
		(net "GND")
	)
	(segment
		(start 60.947046 -276.366732)
		(end 62.267846 -276.366732)
		(width 0.381)
		(layer "F.Cu")
		(net "GND")
	)
	(segment
		(start 54.724046 -208.366614)
		(end 53.403246 -208.366614)
		(width 0.381)
		(layer "F.Cu")
		(net "GND")
	)
	(segment
		(start 126.317248 -287.288986)
		(end 126.316994 -287.28924)
		(width 0.254)
		(layer "F.Cu")
		(net "GND")
	)
	(segment
		(start 94.364048 -263.96442)
		(end 94.364048 -264.500106)
		(width 0.254)
		(layer "F.Cu")
		(net "GND")
	)
	(segment
		(start 267.724382 -275.516594)
		(end 268.829282 -275.516594)
		(width 0.381)
		(layer "F.Cu")
		(net "GND")
	)
	(segment
		(start 370.858034 -246.086376)
		(end 370.858034 -245.55069)
		(width 0.2032)
		(layer "F.Cu")
		(net "GND")
	)
	(segment
		(start 428.279814 -276.366732)
		(end 429.384714 -276.366732)
		(width 0.381)
		(layer "F.Cu")
		(net "GND")
	)
	(segment
		(start 33.767014 -310.366664)
		(end 34.871914 -310.366664)
		(width 0.381)
		(layer "F.Cu")
		(net "GND")
	)
	(segment
		(start 325.98995 -45.535088)
		(end 326.913494 -45.535088)
		(width 0.2032)
		(layer "F.Cu")
		(net "GND")
	)
	(segment
		(start 312.987182 -200.716642)
		(end 314.092082 -200.716642)
		(width 0.381)
		(layer "F.Cu")
		(net "GND")
	)
	(segment
		(start 463.659982 -312.91657)
		(end 462.555082 -312.91657)
		(width 0.381)
		(layer "F.Cu")
		(net "GND")
	)
	(segment
		(start 173.900846 -313.766708)
		(end 175.005746 -313.766708)
		(width 0.381)
		(layer "F.Cu")
		(net "GND")
	)
	(segment
		(start 178.1556 -115.375436)
		(end 177.75555 -115.775486)
		(width 0.3556)
		(layer "F.Cu")
		(net "GND")
	)
	(segment
		(start 131.016248 -267.219938)
		(end 131.016248 -267.755624)
		(width 0.254)
		(layer "F.Cu")
		(net "GND")
	)
	(segment
		(start 260.180582 -271.266666)
		(end 259.075682 -271.266666)
		(width 0.381)
		(layer "F.Cu")
		(net "GND")
	)
	(segment
		(start 337.495134 -228.99497)
		(end 337.495134 -228.459284)
		(width 0.2032)
		(layer "F.Cu")
		(net "GND")
	)
	(segment
		(start 197.637146 -287.416748)
		(end 196.532246 -287.416748)
		(width 0.381)
		(layer "F.Cu")
		(net "GND")
	)
	(segment
		(start 129.606294 -261.522718)
		(end 129.606294 -262.058404)
		(width 0.254)
		(layer "F.Cu")
		(net "GND")
	)
	(segment
		(start 92.844112 -242.830858)
		(end 92.844112 -242.295172)
		(width 0.2032)
		(layer "F.Cu")
		(net "GND")
	)
	(segment
		(start 376.966734 -232.250488)
		(end 376.966734 -231.714548)
		(width 0.2032)
		(layer "F.Cu")
		(net "GND")
	)
	(segment
		(start 162.913314 -213.46668)
		(end 161.808414 -213.46668)
		(width 0.381)
		(layer "F.Cu")
		(net "GND")
	)
	(segment
		(start 370.967762 -285.939484)
		(end 370.967762 -286.475424)
		(width 0.2032)
		(layer "F.Cu")
		(net "GND")
	)
	(segment
		(start 384.16484 -287.606994)
		(end 384.16484 -288.063432)
		(width 0.254)
		(layer "F.Cu")
		(net "GND")
	)
	(segment
		(start 406.753314 -270.416782)
		(end 407.858214 -270.416782)
		(width 0.381)
		(layer "F.Cu")
		(net "GND")
	)
	(segment
		(start 385.424934 -240.389156)
		(end 384.955034 -240.667286)
		(width 0.254)
		(layer "F.Cu")
		(net "GND")
	)
	(segment
		(start 106.471466 -230.622602)
		(end 106.471466 -230.086662)
		(width 0.2032)
		(layer "F.Cu")
		(net "GND")
	)
	(segment
		(start 373.787416 -282.68422)
		(end 373.787416 -283.219906)
		(width 0.254)
		(layer "F.Cu")
		(net "GND")
	)
	(segment
		(start 300.21022 -418.62756)
		(end 300.21022 -417.990528)
		(width 0.3556)
		(layer "F.Cu")
		(net "GND")
	)
	(segment
		(start 254.975614 -285.716726)
		(end 256.080514 -285.716726)
		(width 0.381)
		(layer "F.Cu")
		(net "GND")
	)
	(segment
		(start 348.30258 -247.714262)
		(end 348.30258 -247.178576)
		(width 0.2032)
		(layer "F.Cu")
		(net "GND")
	)
	(segment
		(start 348.882716 -284.033468)
		(end 348.882462 -284.033722)
		(width 0.254)
		(layer "F.Cu")
		(net "GND")
	)
	(segment
		(start 334.205834 -242.830858)
		(end 334.205834 -242.294918)
		(width 0.2032)
		(layer "F.Cu")
		(net "GND")
	)
	(segment
		(start 12.240514 -232.166668)
		(end 13.345414 -232.166668)
		(width 0.381)
		(layer "F.Cu")
		(net "GND")
	)
	(segment
		(start 159.918146 -258.516628)
		(end 158.813246 -258.516628)
		(width 0.381)
		(layer "F.Cu")
		(net "GND")
	)
	(segment
		(start 334.205834 -232.528364)
		(end 334.205834 -233.064304)
		(width 0.2032)
		(layer "F.Cu")
		(net "GND")
	)
	(segment
		(start 444.472314 -281.466798)
		(end 445.577214 -281.466798)
		(width 0.381)
		(layer "F.Cu")
		(net "GND")
	)
	(segment
		(start 97.653094 -261.522718)
		(end 97.653094 -262.058658)
		(width 0.2032)
		(layer "F.Cu")
		(net "GND")
	)
	(segment
		(start 361.569762 -281.05608)
		(end 361.569762 -281.59202)
		(width 0.254)
		(layer "F.Cu")
		(net "GND")
	)
	(segment
		(start 123.857512 -226.553268)
		(end 123.857512 -226.017582)
		(width 0.254)
		(layer "F.Cu")
		(net "GND")
	)
	(segment
		(start 286.255714 -270.416782)
		(end 287.360614 -270.416782)
		(width 0.381)
		(layer "F.Cu")
		(net "GND")
	)
	(segment
		(start 377.43638 -216.78646)
		(end 377.43638 -216.250774)
		(width 0.254)
		(layer "F.Cu")
		(net "GND")
	)
	(segment
		(start 56.398414 -241.516662)
		(end 57.503314 -241.516662)
		(width 0.381)
		(layer "F.Cu")
		(net "GND")
	)
	(segment
		(start 193.20256 -430.905158)
		(end 193.48958 -430.618138)
		(width 0.3556)
		(layer "F.Cu")
		(net "GND")
	)
	(segment
		(start 31.69793 -424.271948)
		(end 32.30753 -424.271948)
		(width 0.3556)
		(layer "F.Cu")
		(net "GND")
	)
	(segment
		(start 110.23092 -248.527824)
		(end 110.23092 -247.992392)
		(width 0.254)
		(layer "F.Cu")
		(net "GND")
	)
	(segment
		(start 121.977912 -223.297496)
		(end 121.977912 -222.76181)
		(width 0.254)
		(layer "F.Cu")
		(net "GND")
	)
	(segment
		(start 138.424666 -220.855794)
		(end 138.424666 -220.319854)
		(width 0.254)
		(layer "F.Cu")
		(net "GND")
	)
	(segment
		(start 358.17048 -238.76127)
		(end 358.17048 -238.225584)
		(width 0.254)
		(layer "F.Cu")
		(net "GND")
	)
	(segment
		(start 449.677282 -198.166736)
		(end 448.572382 -198.166736)
		(width 0.381)
		(layer "F.Cu")
		(net "GND")
	)
	(segment
		(start 53.403246 -279.766776)
		(end 54.508146 -279.766776)
		(width 0.381)
		(layer "F.Cu")
		(net "GND")
	)
	(segment
		(start 359.580434 -220.041724)
		(end 359.580434 -219.506038)
		(width 0.254)
		(layer "F.Cu")
		(net "GND")
	)
	(segment
		(start 298.62018 -53.384196)
		(end 297.90771 -53.384196)
		(width 0.3556)
		(layer "F.Cu")
		(net "GND")
	)
	(segment
		(start 347.363034 -220.041724)
		(end 347.363034 -219.506038)
		(width 0.254)
		(layer "F.Cu")
		(net "GND")
	)
	(segment
		(start 345.483434 -234.691936)
		(end 345.483434 -234.15625)
		(width 0.254)
		(layer "F.Cu")
		(net "GND")
	)
	(segment
		(start 173.900846 -221.96679)
		(end 172.795946 -221.96679)
		(width 0.381)
		(layer "F.Cu")
		(net "GND")
	)
	(segment
		(start 176.896014 -211.766658)
		(end 178.000914 -211.766658)
		(width 0.381)
		(layer "F.Cu")
		(net "GND")
	)
	(segment
		(start 429.384714 -300.166786)
		(end 430.489614 -300.166786)
		(width 0.381)
		(layer "F.Cu")
		(net "GND")
	)
	(segment
		(start 38.315646 -307.816758)
		(end 37.210746 -307.816758)
		(width 0.381)
		(layer "F.Cu")
		(net "GND")
	)
	(segment
		(start 132.425694 -263.68629)
		(end 132.425948 -263.686544)
		(width 0.2032)
		(layer "F.Cu")
		(net "GND")
	)
	(segment
		(start 132.425694 -268.033754)
		(end 132.425948 -268.569694)
		(width 0.2032)
		(layer "F.Cu")
		(net "GND")
	)
	(segment
		(start 339.954362 -279.96388)
		(end 339.954616 -279.964134)
		(width 0.254)
		(layer "F.Cu")
		(net "GND")
	)
	(segment
		(start 8.140446 -220.266768)
		(end 9.245346 -220.266768)
		(width 0.381)
		(layer "F.Cu")
		(net "GND")
	)
	(segment
		(start 106.030522 -32.781494)
		(end 105.018586 -32.781494)
		(width 0.3556)
		(layer "F.Cu")
		(net "GND")
	)
	(segment
		(start 429.384714 -313.766708)
		(end 430.489614 -313.766708)
		(width 0.381)
		(layer "F.Cu")
		(net "GND")
	)
	(segment
		(start 208.176114 -247.466612)
		(end 209.281014 -247.466612)
		(width 0.381)
		(layer "F.Cu")
		(net "GND")
	)
	(segment
		(start 9.20877 -76.827888)
		(end 9.20877 -77.462888)
		(width 0.3556)
		(layer "F.Cu")
		(net "GND")
	)
	(segment
		(start 376.49658 -223.297496)
		(end 376.49658 -222.76181)
		(width 0.254)
		(layer "F.Cu")
		(net "GND")
	)
	(segment
		(start 346.532962 -289.195002)
		(end 346.532962 -289.807142)
		(width 0.2032)
		(layer "F.Cu")
		(net "GND")
	)
	(segment
		(start 180.339746 -279.766776)
		(end 181.444646 -279.766776)
		(width 0.381)
		(layer "F.Cu")
		(net "GND")
	)
	(segment
		(start 22.123146 -289.11677)
		(end 23.228046 -289.11677)
		(width 0.381)
		(layer "F.Cu")
		(net "GND")
	)
	(segment
		(start 379.319536 -105.883202)
		(end 379.319536 -106.492802)
		(width 0.3556)
		(layer "F.Cu")
		(net "GND")
	)
	(segment
		(start 174.80788 -98.643948)
		(end 174.80788 -97.934018)
		(width 0.3556)
		(layer "F.Cu")
		(net "GND")
	)
	(segment
		(start 339.748876 -54.089046)
		(end 339.748876 -53.149246)
		(width 0.2032)
		(layer "F.Cu")
		(net "GND")
	)
	(segment
		(start 419.502082 -271.266666)
		(end 418.397182 -271.266666)
		(width 0.381)
		(layer "F.Cu")
		(net "GND")
	)
	(segment
		(start 418.130228 -375.08053)
		(end 418.832538 -375.08053)
		(width 0.3556)
		(layer "F.Cu")
		(net "GND")
	)
	(segment
		(start 185.544714 -232.166668)
		(end 184.439814 -232.166668)
		(width 0.381)
		(layer "F.Cu")
		(net "GND")
	)
	(segment
		(start 107.881166 -220.041724)
		(end 107.881166 -219.506038)
		(width 0.254)
		(layer "F.Cu")
		(net "GND")
	)
	(segment
		(start 27.328114 -261.066788)
		(end 28.433014 -261.066788)
		(width 0.381)
		(layer "F.Cu")
		(net "GND")
	)
	(segment
		(start 197.637146 -281.466798)
		(end 196.532246 -281.466798)
		(width 0.381)
		(layer "F.Cu")
		(net "GND")
	)
	(segment
		(start 260.180582 -232.166668)
		(end 259.075682 -232.166668)
		(width 0.381)
		(layer "F.Cu")
		(net "GND")
	)
	(segment
		(start 405.496776 -55.313072)
		(end 405.050244 -55.759604)
		(width 0.3556)
		(layer "F.Cu")
		(net "GND")
	)
	(segment
		(start 304.338482 -289.966654)
		(end 305.443382 -289.966654)
		(width 0.381)
		(layer "F.Cu")
		(net "GND")
	)
	(segment
		(start 156.122878 -132.155946)
		(end 156.33192 -132.155946)
		(width 0.3556)
		(layer "F.Cu")
		(net "GND")
	)
	(segment
		(start 366.15878 -220.041978)
		(end 366.159034 -220.041724)
		(width 0.254)
		(layer "F.Cu")
		(net "GND")
	)
	(segment
		(start 374.61698 -242.830858)
		(end 374.61698 -242.295172)
		(width 0.2032)
		(layer "F.Cu")
		(net "GND")
	)
	(segment
		(start 360.050334 -235.506006)
		(end 360.05008 -235.505752)
		(width 0.2032)
		(layer "F.Cu")
		(net "GND")
	)
	(segment
		(start 349.242634 -220.041724)
		(end 349.242634 -219.506038)
		(width 0.254)
		(layer "F.Cu")
		(net "GND")
	)
	(segment
		(start 33.767014 -222.816674)
		(end 34.871914 -222.816674)
		(width 0.381)
		(layer "F.Cu")
		(net "GND")
	)
	(segment
		(start 350.182434 -220.041724)
		(end 350.182434 -219.506038)
		(width 0.254)
		(layer "F.Cu")
		(net "GND")
	)
	(segment
		(start 38.315646 -295.06672)
		(end 37.210746 -295.06672)
		(width 0.381)
		(layer "F.Cu")
		(net "GND")
	)
	(segment
		(start 166.357046 -261.916672)
		(end 167.461946 -261.916672)
		(width 0.381)
		(layer "F.Cu")
		(net "GND")
	)
	(segment
		(start 296.794682 -295.916604)
		(end 297.899582 -295.916604)
		(width 0.381)
		(layer "F.Cu")
		(net "GND")
	)
	(segment
		(start 383.655062 -263.96442)
		(end 383.655062 -264.50036)
		(width 0.254)
		(layer "F.Cu")
		(net "GND")
	)
	(segment
		(start 190.093346 -242.3668)
		(end 188.988446 -242.3668)
		(width 0.381)
		(layer "F.Cu")
		(net "GND")
	)
	(segment
		(start 339.484716 -278.614378)
		(end 339.484462 -279.150318)
		(width 0.2032)
		(layer "F.Cu")
		(net "GND")
	)
	(segment
		(start 35.976814 -303.566576)
		(end 34.871914 -303.566576)
		(width 0.381)
		(layer "F.Cu")
		(net "GND")
	)
	(segment
		(start 14.579346 -263.616694)
		(end 15.684246 -263.616694)
		(width 0.381)
		(layer "F.Cu")
		(net "GND")
	)
	(segment
		(start 361.569762 -282.683966)
		(end 361.569762 -283.219906)
		(width 0.254)
		(layer "F.Cu")
		(net "GND")
	)
	(segment
		(start 59.3852 -41.323768)
		(end 58.90006 -41.323768)
		(width 0.3556)
		(layer "F.Cu")
		(net "GND")
	)
	(segment
		(start 90.024712 -216.78646)
		(end 90.024966 -216.25052)
		(width 0.254)
		(layer "F.Cu")
		(net "GND")
	)
	(segment
		(start 260.180582 -275.516594)
		(end 259.075682 -275.516594)
		(width 0.381)
		(layer "F.Cu")
		(net "GND")
	)
	(segment
		(start 128.556512 -237.947454)
		(end 128.556766 -237.947454)
		(width 0.254)
		(layer "F.Cu")
		(net "GND")
	)
	(segment
		(start 134.775448 -285.6611)
		(end 134.775194 -285.661354)
		(width 0.2032)
		(layer "F.Cu")
		(net "GND")
	)
	(segment
		(start 85.813138 -339.297772)
		(end 85.813138 -339.586316)
		(width 0.1778)
		(layer "F.Cu")
		(net "GND")
	)
	(segment
		(start 214.615014 -210.066636)
		(end 215.719914 -210.066636)
		(width 0.381)
		(layer "F.Cu")
		(net "GND")
	)
	(segment
		(start 19.784314 -216.866724)
		(end 18.679414 -216.866724)
		(width 0.381)
		(layer "F.Cu")
		(net "GND")
	)
	(segment
		(start 343.81948 -52.679346)
		(end 343.55024 -52.209446)
		(width 0.254)
		(layer "F.Cu")
		(net "GND")
	)
	(segment
		(start 123.38304 -412.735268)
		(end 124.00915 -413.361378)
		(width 0.508)
		(layer "F.Cu")
		(net "GND")
	)
	(segment
		(start 294.904414 -221.96679)
		(end 293.799514 -221.96679)
		(width 0.381)
		(layer "F.Cu")
		(net "GND")
	)
	(segment
		(start 118.798848 -276.986492)
		(end 118.798848 -277.522432)
		(width 0.254)
		(layer "F.Cu")
		(net "GND")
	)
	(segment
		(start 456.216258 -380.864872)
		(end 456.621388 -380.864872)
		(width 0.381)
		(layer "F.Cu")
		(net "GND")
	)
	(segment
		(start 413.192214 -281.466798)
		(end 414.297114 -281.466798)
		(width 0.381)
		(layer "F.Cu")
		(net "GND")
	)
	(segment
		(start 48.854614 -305.266598)
		(end 49.959514 -305.266598)
		(width 0.381)
		(layer "F.Cu")
		(net "GND")
	)
	(segment
		(start 256.080514 -285.716726)
		(end 257.185414 -285.716726)
		(width 0.381)
		(layer "F.Cu")
		(net "GND")
	)
	(segment
		(start 289.250882 -200.716642)
		(end 290.355782 -200.716642)
		(width 0.381)
		(layer "F.Cu")
		(net "GND")
	)
	(segment
		(start 99.388422 -414.376616)
		(end 99.383342 -414.371536)
		(width 0.3556)
		(layer "F.Cu")
		(net "GND")
	)
	(segment
		(start 200.632314 -303.566576)
		(end 201.737214 -303.566576)
		(width 0.381)
		(layer "F.Cu")
		(net "GND")
	)
	(segment
		(start 448.572382 -305.266598)
		(end 447.467482 -305.266598)
		(width 0.381)
		(layer "F.Cu")
		(net "GND")
	)
	(segment
		(start 26.63825 -128.364996)
		(end 26.63825 -127.348996)
		(width 0.381)
		(layer "F.Cu")
		(net "GND")
	)
	(segment
		(start 191.983614 -230.466646)
		(end 193.088514 -230.466646)
		(width 0.381)
		(layer "F.Cu")
		(net "GND")
	)
	(segment
		(start 378.016516 -257.45313)
		(end 378.016262 -257.98907)
		(width 0.2032)
		(layer "F.Cu")
		(net "GND")
	)
	(segment
		(start 346.559378 -58.609992)
		(end 347.214698 -58.609992)
		(width 0.2032)
		(layer "F.Cu")
		(net "GND")
	)
	(segment
		(start 119.738648 -283.497782)
		(end 119.738648 -284.033468)
		(width 0.254)
		(layer "F.Cu")
		(net "GND")
	)
	(segment
		(start 120.678448 -282.405582)
		(end 120.678194 -282.405836)
		(width 0.254)
		(layer "F.Cu")
		(net "GND")
	)
	(segment
		(start 63.942214 -278.916638)
		(end 65.047114 -278.916638)
		(width 0.381)
		(layer "F.Cu")
		(net "GND")
	)
	(segment
		(start 421.840914 -216.016586)
		(end 422.945814 -216.016586)
		(width 0.381)
		(layer "F.Cu")
		(net "GND")
	)
	(segment
		(start 122.558048 -255.825498)
		(end 122.558048 -256.361438)
		(width 0.2032)
		(layer "F.Cu")
		(net "GND")
	)
	(segment
		(start 263.624314 -315.46673)
		(end 264.729214 -315.46673)
		(width 0.381)
		(layer "F.Cu")
		(net "GND")
	)
	(segment
		(start 88.615266 -220.855794)
		(end 88.615266 -220.319854)
		(width 0.2032)
		(layer "F.Cu")
		(net "GND")
	)
	(segment
		(start 100.362512 -216.250774)
		(end 100.362766 -216.25052)
		(width 0.254)
		(layer "F.Cu")
		(net "GND")
	)
	(segment
		(start 263.624314 -250.016772)
		(end 264.729214 -250.016772)
		(width 0.381)
		(layer "F.Cu")
		(net "GND")
	)
	(segment
		(start 433.484782 -316.316614)
		(end 434.589682 -316.316614)
		(width 0.381)
		(layer "F.Cu")
		(net "GND")
	)
	(segment
		(start 88.43264 -342.270334)
		(end 87.945976 -342.270334)
		(width 0.3556)
		(layer "F.Cu")
		(net "GND")
	)
	(segment
		(start 7.035546 -197.316598)
		(end 8.140446 -197.316598)
		(width 0.381)
		(layer "F.Cu")
		(net "GND")
	)
	(segment
		(start 44.754546 -307.816758)
		(end 45.859446 -307.816758)
		(width 0.381)
		(layer "F.Cu")
		(net "GND")
	)
	(segment
		(start 88.145366 -224.925382)
		(end 88.145366 -224.389442)
		(width 0.254)
		(layer "F.Cu")
		(net "GND")
	)
	(segment
		(start 49.959514 -219.41663)
		(end 51.064414 -219.41663)
		(width 0.381)
		(layer "F.Cu")
		(net "GND")
	)
	(segment
		(start 367.678716 -288.381186)
		(end 367.678716 -288.917126)
		(width 0.254)
		(layer "F.Cu")
		(net "GND")
	)
	(segment
		(start 89.554812 -227.36683)
		(end 89.554812 -226.831144)
		(width 0.2032)
		(layer "F.Cu")
		(net "GND")
	)
	(segment
		(start 113.519712 -247.714262)
		(end 113.519712 -247.179084)
		(width 0.254)
		(layer "F.Cu")
		(net "GND")
	)
	(segment
		(start 366.738916 -280.242264)
		(end 366.738916 -280.77795)
		(width 0.254)
		(layer "F.Cu")
		(net "GND")
	)
	(segment
		(start 414.297114 -221.96679)
		(end 415.402014 -221.96679)
		(width 0.381)
		(layer "F.Cu")
		(net "GND")
	)
	(segment
		(start 169.132504 -210.066636)
		(end 170.457114 -210.066636)
		(width 0.381)
		(layer "F.Cu")
		(net "GND")
	)
	(segment
		(start 349.24238 -229.808786)
		(end 349.24238 -229.272846)
		(width 0.2032)
		(layer "F.Cu")
		(net "GND")
	)
	(segment
		(start 39.420546 -221.96679)
		(end 38.315646 -221.96679)
		(width 0.381)
		(layer "F.Cu")
		(net "GND")
	)
	(segment
		(start 262.519414 -197.316598)
		(end 263.624314 -197.316598)
		(width 0.381)
		(layer "F.Cu")
		(net "GND")
	)
	(segment
		(start 378.956316 -267.755624)
		(end 378.956062 -267.755878)
		(width 0.254)
		(layer "F.Cu")
		(net "GND")
	)
	(segment
		(start 377.668536 -96.212152)
		(end 377.668536 -95.081852)
		(width 0.3556)
		(layer "F.Cu")
		(net "GND")
	)
	(segment
		(start 108.925106 -98.959416)
		(end 109.625384 -98.959416)
		(width 0.3556)
		(layer "F.Cu")
		(net "GND")
	)
	(segment
		(start 41.310814 -196.466714)
		(end 42.415714 -196.466714)
		(width 0.381)
		(layer "F.Cu")
		(net "GND")
	)
	(segment
		(start 120.568466 -228.99497)
		(end 120.568212 -228.994716)
		(width 0.254)
		(layer "F.Cu")
		(net "GND")
	)
	(segment
		(start 333.26578 -228.1809)
		(end 333.26578 -227.64496)
		(width 0.2032)
		(layer "F.Cu")
		(net "GND")
	)
	(segment
		(start 138.424666 -217.064336)
		(end 138.424666 -217.600276)
		(width 0.2032)
		(layer "F.Cu")
		(net "GND")
	)
	(segment
		(start 341.37727 -52.209446)
		(end 341.37727 -51.269646)
		(width 0.2032)
		(layer "F.Cu")
		(net "GND")
	)
	(segment
		(start 88.615266 -245.27256)
		(end 88.615012 -245.272306)
		(width 0.2032)
		(layer "F.Cu")
		(net "GND")
	)
	(segment
		(start 463.659982 -232.166668)
		(end 464.764882 -232.166668)
		(width 0.381)
		(layer "F.Cu")
		(net "GND")
	)
	(segment
		(start 432.379882 -306.96662)
		(end 433.484782 -306.96662)
		(width 0.381)
		(layer "F.Cu")
		(net "GND")
	)
	(segment
		(start 93.783912 -247.714262)
		(end 93.783912 -247.178576)
		(width 0.2032)
		(layer "F.Cu")
		(net "GND")
	)
	(segment
		(start 369.558316 -278.614378)
		(end 369.558062 -279.150318)
		(width 0.254)
		(layer "F.Cu")
		(net "GND")
	)
	(segment
		(start 121.618248 -281.869896)
		(end 121.618248 -282.405582)
		(width 0.254)
		(layer "F.Cu")
		(net "GND")
	)
	(segment
		(start 350.762316 -268.84757)
		(end 350.762062 -268.847824)
		(width 0.2032)
		(layer "F.Cu")
		(net "GND")
	)
	(segment
		(start 158.813246 -258.516628)
		(end 157.708346 -258.516628)
		(width 0.381)
		(layer "F.Cu")
		(net "GND")
	)
	(segment
		(start 98.123248 -255.825498)
		(end 98.123248 -256.361184)
		(width 0.2032)
		(layer "F.Cu")
		(net "GND")
	)
	(segment
		(start 260.180582 -226.216718)
		(end 259.075682 -226.216718)
		(width 0.381)
		(layer "F.Cu")
		(net "GND")
	)
	(segment
		(start 12.240514 -247.466612)
		(end 13.345414 -247.466612)
		(width 0.381)
		(layer "F.Cu")
		(net "GND")
	)
	(segment
		(start 414.297114 -292.516814)
		(end 415.402014 -292.516814)
		(width 0.381)
		(layer "F.Cu")
		(net "GND")
	)
	(segment
		(start 169.21099 -57.555638)
		(end 166.859204 -57.555638)
		(width 0.3556)
		(layer "F.Cu")
		(net "GND")
	)
	(segment
		(start 89.554812 -250.15571)
		(end 89.554812 -249.620024)
		(width 0.2032)
		(layer "F.Cu")
		(net "GND")
	)
	(segment
		(start 349.352362 -263.150604)
		(end 349.352362 -263.686544)
		(width 0.254)
		(layer "F.Cu")
		(net "GND")
	)
	(segment
		(start 463.659982 -233.86669)
		(end 464.764882 -233.86669)
		(width 0.381)
		(layer "F.Cu")
		(net "GND")
	)
	(segment
		(start 420.736014 -197.316598)
		(end 421.840914 -197.316598)
		(width 0.381)
		(layer "F.Cu")
		(net "GND")
	)
	(segment
		(start 214.615014 -305.266598)
		(end 215.719914 -305.266598)
		(width 0.381)
		(layer "F.Cu")
		(net "GND")
	)
	(segment
		(start 178.000914 -297.616626)
		(end 176.896014 -297.616626)
		(width 0.381)
		(layer "F.Cu")
		(net "GND")
	)
	(segment
		(start 193.538094 -113.263934)
		(end 194.150996 -113.263934)
		(width 0.3556)
		(layer "F.Cu")
		(net "GND")
	)
	(segment
		(start 199.527414 -247.466612)
		(end 200.632314 -247.466612)
		(width 0.381)
		(layer "F.Cu")
		(net "GND")
	)
	(segment
		(start 134.305294 -258.2672)
		(end 134.305294 -258.802886)
		(width 0.2032)
		(layer "F.Cu")
		(net "GND")
	)
	(segment
		(start 7.035546 -248.31675)
		(end 8.140446 -248.31675)
		(width 0.381)
		(layer "F.Cu")
		(net "GND")
	)
	(segment
		(start 378.846334 -227.367084)
		(end 378.846334 -226.831144)
		(width 0.2032)
		(layer "F.Cu")
		(net "GND")
	)
	(segment
		(start 301.128684 -15.598394)
		(end 301.154084 -15.572994)
		(width 0.3556)
		(layer "F.Cu")
		(net "GND")
	)
	(segment
		(start 384.015234 -236.319822)
		(end 384.015234 -235.783882)
		(width 0.254)
		(layer "F.Cu")
		(net "GND")
	)
	(segment
		(start 42.415714 -215.166702)
		(end 41.310814 -215.166702)
		(width 0.381)
		(layer "F.Cu")
		(net "GND")
	)
	(segment
		(start 406.753314 -220.266768)
		(end 407.858214 -220.266768)
		(width 0.381)
		(layer "F.Cu")
		(net "GND")
	)
	(segment
		(start 452.016114 -201.56678)
		(end 450.911214 -201.56678)
		(width 0.381)
		(layer "F.Cu")
		(net "GND")
	)
	(segment
		(start 199.527414 -230.466646)
		(end 200.632314 -230.466646)
		(width 0.381)
		(layer "F.Cu")
		(net "GND")
	)
	(segment
		(start 135.714994 -259.093462)
		(end 135.71474 -259.616956)
		(width 0.2032)
		(layer "F.Cu")
		(net "GND")
	)
	(segment
		(start 334.315562 -269.66164)
		(end 333.845662 -269.38351)
		(width 0.254)
		(layer "F.Cu")
		(net "GND")
	)
	(segment
		(start 215.719914 -215.166702)
		(end 216.824814 -215.166702)
		(width 0.381)
		(layer "F.Cu")
		(net "GND")
	)
	(segment
		(start 420.282116 -136.162034)
		(end 419.590474 -136.162034)
		(width 0.381)
		(layer "F.Cu")
		(net "GND")
	)
	(segment
		(start 95.193612 -230.622348)
		(end 95.193612 -230.086662)
		(width 0.2032)
		(layer "F.Cu")
		(net "GND")
	)
	(segment
		(start 311.882282 -230.466646)
		(end 312.987182 -230.466646)
		(width 0.381)
		(layer "F.Cu")
		(net "GND")
	)
	(segment
		(start 164.018214 -213.46668)
		(end 162.913314 -213.46668)
		(width 0.381)
		(layer "F.Cu")
		(net "GND")
	)
	(segment
		(start 458.455014 -278.066754)
		(end 459.559914 -278.066754)
		(width 0.381)
		(layer "F.Cu")
		(net "GND")
	)
	(segment
		(start 416.556952 -11.26998)
		(end 416.556952 -10.16508)
		(width 0.3556)
		(layer "F.Cu")
		(net "GND")
	)
	(segment
		(start 181.444646 -216.016586)
		(end 182.549546 -216.016586)
		(width 0.381)
		(layer "F.Cu")
		(net "GND")
	)
	(segment
		(start 352.171762 -279.96388)
		(end 352.172016 -279.964134)
		(width 0.2032)
		(layer "F.Cu")
		(net "GND")
	)
	(segment
		(start 309.992014 -296.766742)
		(end 308.887114 -296.766742)
		(width 0.381)
		(layer "F.Cu")
		(net "GND")
	)
	(segment
		(start 436.928514 -285.716726)
		(end 438.033414 -285.716726)
		(width 0.381)
		(layer "F.Cu")
		(net "GND")
	)
	(segment
		(start 169.352214 -245.76659)
		(end 170.457114 -245.76659)
		(width 0.381)
		(layer "F.Cu")
		(net "GND")
	)
	(segment
		(start 19.784314 -297.616626)
		(end 20.889214 -297.616626)
		(width 0.381)
		(layer "F.Cu")
		(net "GND")
	)
	(segment
		(start 207.071214 -269.566644)
		(end 208.176114 -269.566644)
		(width 0.381)
		(layer "F.Cu")
		(net "GND")
	)
	(segment
		(start 18.679414 -282.316682)
		(end 19.784314 -282.316682)
		(width 0.381)
		(layer "F.Cu")
		(net "GND")
	)
	(segment
		(start 296.794682 -233.86669)
		(end 297.899582 -233.86669)
		(width 0.381)
		(layer "F.Cu")
		(net "GND")
	)
	(segment
		(start 422.945814 -276.366732)
		(end 421.840914 -276.366732)
		(width 0.381)
		(layer "F.Cu")
		(net "GND")
	)
	(segment
		(start 196.532246 -315.46673)
		(end 195.427346 -315.46673)
		(width 0.381)
		(layer "F.Cu")
		(net "GND")
	)
	(segment
		(start 333.375762 -282.683966)
		(end 333.375762 -283.219906)
		(width 0.2032)
		(layer "F.Cu")
		(net "GND")
	)
	(segment
		(start 452.016114 -317.166752)
		(end 450.911214 -317.166752)
		(width 0.381)
		(layer "F.Cu")
		(net "GND")
	)
	(segment
		(start 311.666382 -210.066636)
		(end 312.987182 -210.066636)
		(width 0.381)
		(layer "F.Cu")
		(net "GND")
	)
	(segment
		(start 340.894162 -273.452844)
		(end 340.894416 -273.453098)
		(width 0.2032)
		(layer "F.Cu")
		(net "GND")
	)
	(segment
		(start 333.23657 -42.811446)
		(end 332.697328 -42.811446)
		(width 0.2032)
		(layer "F.Cu")
		(net "GND")
	)
	(segment
		(start 358.506268 -335.541112)
		(end 358.858566 -335.541112)
		(width 0.2032)
		(layer "F.Cu")
		(net "GND")
	)
	(segment
		(start 20.889214 -202.416664)
		(end 19.784314 -202.416664)
		(width 0.381)
		(layer "F.Cu")
		(net "GND")
	)
	(segment
		(start 261.285482 -262.76681)
		(end 260.180582 -262.76681)
		(width 0.381)
		(layer "F.Cu")
		(net "GND")
	)
	(segment
		(start 443.367414 -279.766776)
		(end 444.472314 -279.766776)
		(width 0.381)
		(layer "F.Cu")
		(net "GND")
	)
	(segment
		(start 293.799514 -251.716794)
		(end 292.694614 -251.716794)
		(width 0.381)
		(layer "F.Cu")
		(net "GND")
	)
	(segment
		(start 312.987182 -238.116618)
		(end 314.307982 -238.116618)
		(width 0.381)
		(layer "F.Cu")
		(net "GND")
	)
	(segment
		(start 14.579346 -295.06672)
		(end 15.684246 -295.06672)
		(width 0.381)
		(layer "F.Cu")
		(net "GND")
	)
	(segment
		(start 29.666946 -272.116804)
		(end 30.771846 -272.116804)
		(width 0.381)
		(layer "F.Cu")
		(net "GND")
	)
	(segment
		(start 52.082446 -292.516814)
		(end 53.403246 -292.516814)
		(width 0.381)
		(layer "F.Cu")
		(net "GND")
	)
	(segment
		(start 232.000044 -49.76495)
		(end 230.984044 -49.76495)
		(width 0.381)
		(layer "F.Cu")
		(net "GND")
	)
	(segment
		(start 193.088514 -303.566576)
		(end 194.193414 -303.566576)
		(width 0.381)
		(layer "F.Cu")
		(net "GND")
	)
	(segment
		(start 208.176114 -258.516628)
		(end 209.281014 -258.516628)
		(width 0.381)
		(layer "F.Cu")
		(net "GND")
	)
	(segment
		(start 178.000914 -271.266666)
		(end 176.896014 -271.266666)
		(width 0.381)
		(layer "F.Cu")
		(net "GND")
	)
	(segment
		(start 362.3945 -412.341314)
		(end 363.0295 -412.341314)
		(width 0.3556)
		(layer "F.Cu")
		(net "GND")
	)
	(segment
		(start 452.016114 -217.716608)
		(end 450.911214 -217.716608)
		(width 0.381)
		(layer "F.Cu")
		(net "GND")
	)
	(segment
		(start 101.412294 -261.522718)
		(end 101.412294 -262.058404)
		(width 0.254)
		(layer "F.Cu")
		(net "GND")
	)
	(segment
		(start 199.527414 -303.566576)
		(end 200.632314 -303.566576)
		(width 0.381)
		(layer "F.Cu")
		(net "GND")
	)
	(segment
		(start 428.279814 -212.616796)
		(end 429.384714 -212.616796)
		(width 0.381)
		(layer "F.Cu")
		(net "GND")
	)
	(segment
		(start 350.652334 -217.600276)
		(end 350.652334 -217.064336)
		(width 0.2032)
		(layer "F.Cu")
		(net "GND")
	)
	(segment
		(start 190.093346 -223.666558)
		(end 188.988446 -223.666558)
		(width 0.381)
		(layer "F.Cu")
		(net "GND")
	)
	(segment
		(start 301.343314 -214.316564)
		(end 302.448214 -214.316564)
		(width 0.381)
		(layer "F.Cu")
		(net "GND")
	)
	(segment
		(start 294.904414 -199.01662)
		(end 293.799514 -199.01662)
		(width 0.381)
		(layer "F.Cu")
		(net "GND")
	)
	(segment
		(start 92.954094 -253.383796)
		(end 92.954094 -253.919482)
		(width 0.2032)
		(layer "F.Cu")
		(net "GND")
	)
	(segment
		(start 139.004294 -263.150604)
		(end 139.474448 -262.872474)
		(width 0.254)
		(layer "F.Cu")
		(net "GND")
	)
	(segment
		(start 63.942214 -316.316614)
		(end 65.047114 -316.316614)
		(width 0.381)
		(layer "F.Cu")
		(net "GND")
	)
	(segment
		(start 421.840914 -221.96679)
		(end 422.945814 -221.96679)
		(width 0.381)
		(layer "F.Cu")
		(net "GND")
	)
	(segment
		(start 189.25032 -427.319948)
		(end 188.63437 -427.319948)
		(width 0.3556)
		(layer "F.Cu")
		(net "GND")
	)
	(segment
		(start 188.988446 -301.866808)
		(end 190.093346 -301.866808)
		(width 0.381)
		(layer "F.Cu")
		(net "GND")
	)
	(segment
		(start 254.975614 -221.96679)
		(end 256.080514 -221.96679)
		(width 0.381)
		(layer "F.Cu")
		(net "GND")
	)
	(segment
		(start 182.337964 -335.483962)
		(end 183.353964 -335.483962)
		(width 0.508)
		(layer "F.Cu")
		(net "GND")
	)
	(segment
		(start 47.78629 -144.626838)
		(end 48.28794 -144.626838)
		(width 0.3556)
		(layer "F.Cu")
		(net "GND")
	)
	(segment
		(start 60.947046 -265.316716)
		(end 62.051946 -265.316716)
		(width 0.381)
		(layer "F.Cu")
		(net "GND")
	)
	(segment
		(start 135.605266 -243.108988)
		(end 135.605266 -243.644928)
		(width 0.254)
		(layer "F.Cu")
		(net "GND")
	)
	(segment
		(start 354.521516 -272.639028)
		(end 354.521262 -272.639282)
		(width 0.2032)
		(layer "F.Cu")
		(net "GND")
	)
	(segment
		(start 11.135614 -310.366664)
		(end 12.240514 -310.366664)
		(width 0.381)
		(layer "F.Cu")
		(net "GND")
	)
	(segment
		(start 275.268182 -221.116652)
		(end 276.373082 -221.116652)
		(width 0.381)
		(layer "F.Cu")
		(net "GND")
	)
	(segment
		(start 377.43638 -223.297496)
		(end 377.43638 -222.76181)
		(width 0.254)
		(layer "F.Cu")
		(net "GND")
	)
	(segment
		(start 296.794682 -266.1666)
		(end 297.899582 -266.1666)
		(width 0.381)
		(layer "F.Cu")
		(net "GND")
	)
	(segment
		(start 427.045882 -312.91657)
		(end 425.940982 -312.91657)
		(width 0.381)
		(layer "F.Cu")
		(net "GND")
	)
	(segment
		(start 49.959514 -308.666642)
		(end 51.064414 -308.666642)
		(width 0.381)
		(layer "F.Cu")
		(net "GND")
	)
	(segment
		(start 8.140446 -208.366614)
		(end 9.245346 -208.366614)
		(width 0.381)
		(layer "F.Cu")
		(net "GND")
	)
	(segment
		(start 7.454646 -101.166168)
		(end 7.495286 -101.125528)
		(width 0.3556)
		(layer "F.Cu")
		(net "GND")
	)
	(segment
		(start 63.942214 -297.616626)
		(end 65.047114 -297.616626)
		(width 0.381)
		(layer "F.Cu")
		(net "GND")
	)
	(segment
		(start 353.00158 -216.78646)
		(end 353.00158 -216.250774)
		(width 0.254)
		(layer "F.Cu")
		(net "GND")
	)
	(segment
		(start 413.192214 -199.01662)
		(end 414.297114 -199.01662)
		(width 0.381)
		(layer "F.Cu")
		(net "GND")
	)
	(segment
		(start 444.472314 -307.816758)
		(end 445.577214 -307.816758)
		(width 0.381)
		(layer "F.Cu")
		(net "GND")
	)
	(segment
		(start 359.58018 -228.1809)
		(end 359.580434 -228.180646)
		(width 0.2032)
		(layer "F.Cu")
		(net "GND")
	)
	(segment
		(start 285.150814 -290.816792)
		(end 286.255714 -290.816792)
		(width 0.381)
		(layer "F.Cu")
		(net "GND")
	)
	(segment
		(start 347.214698 -52.952396)
		(end 346.945966 -53.063648)
		(width 0.2032)
		(layer "F.Cu")
		(net "GND")
	)
	(segment
		(start 400.24685 -11.26998)
		(end 400.24685 -12.37488)
		(width 0.3556)
		(layer "F.Cu")
		(net "GND")
	)
	(segment
		(start 123.027694 -272.917158)
		(end 123.027694 -273.453098)
		(width 0.2032)
		(layer "F.Cu")
		(net "GND")
	)
	(segment
		(start 306.017422 -435.596538)
		(end 306.570126 -436.149242)
		(width 0.3556)
		(layer "F.Cu")
		(net "GND")
	)
	(segment
		(start 345.15171 -43.350434)
		(end 345.554554 -43.948096)
		(width 0.2032)
		(layer "F.Cu")
		(net "GND")
	)
	(segment
		(start 121.977912 -237.947454)
		(end 121.977912 -237.411768)
		(width 0.254)
		(layer "F.Cu")
		(net "GND")
	)
	(segment
		(start 20.024852 -50.999898)
		(end 21.96846 -50.999898)
		(width 0.3556)
		(layer "F.Cu")
		(net "GND")
	)
	(segment
		(start 413.192214 -287.213548)
		(end 413.395414 -287.416748)
		(width 0.381)
		(layer "F.Cu")
		(net "GND")
	)
	(segment
		(start 137.124694 -274.54479)
		(end 136.185148 -275.080984)
		(width 0.254)
		(layer "F.Cu")
		(net "GND")
	)
	(segment
		(start 185.544714 -219.41663)
		(end 186.649614 -219.41663)
		(width 0.381)
		(layer "F.Cu")
		(net "GND")
	)
	(segment
		(start 181.444646 -296.766742)
		(end 180.339746 -296.766742)
		(width 0.381)
		(layer "F.Cu")
		(net "GND")
	)
	(segment
		(start 22.147022 -7.215124)
		(end 22.147022 -8.320024)
		(width 0.3556)
		(layer "F.Cu")
		(net "GND")
	)
	(segment
		(start 359.58018 -218.414346)
		(end 359.58018 -217.87866)
		(width 0.2032)
		(layer "F.Cu")
		(net "GND")
	)
	(segment
		(start 262.519414 -221.96679)
		(end 263.624314 -221.96679)
		(width 0.381)
		(layer "F.Cu")
		(net "GND")
	)
	(segment
		(start 462.316576 -100.470208)
		(end 462.316576 -101.105208)
		(width 0.3556)
		(layer "F.Cu")
		(net "GND")
	)
	(segment
		(start 436.928514 -315.46673)
		(end 438.033414 -315.46673)
		(width 0.381)
		(layer "F.Cu")
		(net "GND")
	)
	(segment
		(start 22.123146 -223.666558)
		(end 23.228046 -223.666558)
		(width 0.381)
		(layer "F.Cu")
		(net "GND")
	)
	(segment
		(start 45.859446 -223.666558)
		(end 46.964346 -223.666558)
		(width 0.381)
		(layer "F.Cu")
		(net "GND")
	)
	(segment
		(start 117.278912 -226.017582)
		(end 117.279166 -226.017328)
		(width 0.254)
		(layer "F.Cu")
		(net "GND")
	)
	(segment
		(start 374.61698 -237.411768)
		(end 374.617234 -237.411514)
		(width 0.254)
		(layer "F.Cu")
		(net "GND")
	)
	(segment
		(start 109.760512 -216.78646)
		(end 109.760512 -216.250774)
		(width 0.254)
		(layer "F.Cu")
		(net "GND")
	)
	(segment
		(start 433.484782 -303.566576)
		(end 434.589682 -303.566576)
		(width 0.381)
		(layer "F.Cu")
		(net "GND")
	)
	(segment
		(start 100.472494 -265.313922)
		(end 100.472748 -265.314176)
		(width 0.254)
		(layer "F.Cu")
		(net "GND")
	)
	(segment
		(start 361.460034 -231.436164)
		(end 361.460034 -230.900478)
		(width 0.2032)
		(layer "F.Cu")
		(net "GND")
	)
	(segment
		(start 429.384714 -238.966756)
		(end 430.489614 -238.966756)
		(width 0.381)
		(layer "F.Cu")
		(net "GND")
	)
	(segment
		(start 215.719914 -295.916604)
		(end 216.824814 -295.916604)
		(width 0.381)
		(layer "F.Cu")
		(net "GND")
	)
	(segment
		(start 199.527414 -210.066636)
		(end 200.632314 -210.066636)
		(width 0.381)
		(layer "F.Cu")
		(net "GND")
	)
	(segment
		(start 372.267734 -227.367084)
		(end 372.267734 -226.831144)
		(width 0.2032)
		(layer "F.Cu")
		(net "GND")
	)
	(segment
		(start 128.556512 -226.553268)
		(end 128.556512 -226.017582)
		(width 0.254)
		(layer "F.Cu")
		(net "GND")
	)
	(segment
		(start 193.088514 -310.366664)
		(end 194.193414 -310.366664)
		(width 0.381)
		(layer "F.Cu")
		(net "GND")
	)
	(segment
		(start 48.854614 -241.516662)
		(end 49.959514 -241.516662)
		(width 0.381)
		(layer "F.Cu")
		(net "GND")
	)
	(segment
		(start 379.31598 -226.553268)
		(end 379.31598 -226.017582)
		(width 0.254)
		(layer "F.Cu")
		(net "GND")
	)
	(segment
		(start 294.904414 -234.716574)
		(end 293.799514 -234.716574)
		(width 0.381)
		(layer "F.Cu")
		(net "GND")
	)
	(segment
		(start 278.711914 -199.01662)
		(end 277.607014 -199.01662)
		(width 0.381)
		(layer "F.Cu")
		(net "GND")
	)
	(segment
		(start 307.782214 -301.866808)
		(end 308.887114 -301.866808)
		(width 0.381)
		(layer "F.Cu")
		(net "GND")
	)
	(segment
		(start 456.116182 -286.56661)
		(end 455.011282 -286.56661)
		(width 0.381)
		(layer "F.Cu")
		(net "GND")
	)
	(segment
		(start 29.346906 -10.16508)
		(end 29.346906 -11.26998)
		(width 0.3556)
		(layer "F.Cu")
		(net "GND")
	)
	(segment
		(start 120.568212 -232.250234)
		(end 120.568212 -231.714548)
		(width 0.2032)
		(layer "F.Cu")
		(net "GND")
	)
	(segment
		(start 101.772212 -245.272306)
		(end 101.772212 -244.73662)
		(width 0.2032)
		(layer "F.Cu")
		(net "GND")
	)
	(segment
		(start 342.19388 -243.644674)
		(end 342.19388 -243.108988)
		(width 0.2032)
		(layer "F.Cu")
		(net "GND")
	)
	(segment
		(start 29.666946 -301.866808)
		(end 30.771846 -301.866808)
		(width 0.381)
		(layer "F.Cu")
		(net "GND")
	)
	(segment
		(start 259.075682 -316.316614)
		(end 260.180582 -316.316614)
		(width 0.381)
		(layer "F.Cu")
		(net "GND")
	)
	(segment
		(start 336.285332 -37.935916)
		(end 336.399632 -38.050216)
		(width 0.2032)
		(layer "F.Cu")
		(net "GND")
	)
	(segment
		(start 27.328114 -282.316682)
		(end 28.433014 -282.316682)
		(width 0.381)
		(layer "F.Cu")
		(net "GND")
	)
	(segment
		(start 170.457114 -289.966654)
		(end 169.352214 -289.966654)
		(width 0.381)
		(layer "F.Cu")
		(net "GND")
	)
	(segment
		(start 30.771846 -217.716608)
		(end 31.876746 -217.716608)
		(width 0.381)
		(layer "F.Cu")
		(net "GND")
	)
	(segment
		(start 211.619846 -238.966756)
		(end 212.724746 -238.966756)
		(width 0.381)
		(layer "F.Cu")
		(net "GND")
	)
	(segment
		(start 358.280716 -268.84757)
		(end 358.102662 -269.025624)
		(width 0.254)
		(layer "F.Cu")
		(net "GND")
	)
	(segment
		(start 92.3925 -93.817948)
		(end 93.140784 -93.817948)
		(width 0.3556)
		(layer "F.Cu")
		(net "GND")
	)
	(segment
		(start 435.823614 -313.766708)
		(end 436.928514 -313.766708)
		(width 0.381)
		(layer "F.Cu")
		(net "GND")
	)
	(segment
		(start 347.510862 -47.44974)
		(end 346.799662 -47.44974)
		(width 0.1524)
		(layer "F.Cu")
		(net "GND")
	)
	(segment
		(start 307.782214 -199.01662)
		(end 308.887114 -199.01662)
		(width 0.381)
		(layer "F.Cu")
		(net "GND")
	)
	(segment
		(start 101.302312 -241.203226)
		(end 101.302566 -241.202972)
		(width 0.254)
		(layer "F.Cu")
		(net "GND")
	)
	(segment
		(start 305.443382 -238.116618)
		(end 306.764182 -238.116618)
		(width 0.381)
		(layer "F.Cu")
		(net "GND")
	)
	(segment
		(start 78.276704 -343.391998)
		(end 77.984096 -343.391998)
		(width 0.2032)
		(layer "F.Cu")
		(net "GND")
	)
	(segment
		(start 286.255714 -220.266768)
		(end 287.360614 -220.266768)
		(width 0.381)
		(layer "F.Cu")
		(net "GND")
	)
	(segment
		(start 309.992014 -258.516628)
		(end 308.887114 -258.516628)
		(width 0.381)
		(layer "F.Cu")
		(net "GND")
	)
	(segment
		(start 138.894312 -224.389696)
		(end 138.894566 -224.389442)
		(width 0.254)
		(layer "F.Cu")
		(net "GND")
	)
	(segment
		(start 448.572382 -289.966654)
		(end 447.467482 -289.966654)
		(width 0.381)
		(layer "F.Cu")
		(net "GND")
	)
	(segment
		(start 294.229028 -52.041298)
		(end 294.825928 -52.041298)
		(width 0.3556)
		(layer "F.Cu")
		(net "GND")
	)
	(segment
		(start 26.223214 -222.816674)
		(end 27.328114 -222.816674)
		(width 0.381)
		(layer "F.Cu")
		(net "GND")
	)
	(segment
		(start 311.666382 -272.966688)
		(end 312.987182 -272.966688)
		(width 0.381)
		(layer "F.Cu")
		(net "GND")
	)
	(segment
		(start 363.449362 -271.289272)
		(end 363.449616 -271.825212)
		(width 0.2032)
		(layer "F.Cu")
		(net "GND")
	)
	(segment
		(start 59.842146 -268.71676)
		(end 60.947046 -268.71676)
		(width 0.381)
		(layer "F.Cu")
		(net "GND")
	)
	(segment
		(start 443.367414 -251.716794)
		(end 444.472314 -251.716794)
		(width 0.381)
		(layer "F.Cu")
		(net "GND")
	)
	(segment
		(start 166.357046 -290.816792)
		(end 167.461946 -290.816792)
		(width 0.381)
		(layer "F.Cu")
		(net "GND")
	)
	(segment
		(start 339.484716 -275.894546)
		(end 339.484462 -275.8948)
		(width 0.2032)
		(layer "F.Cu")
		(net "GND")
	)
	(segment
		(start 340.42477 -281.87015)
		(end 340.424516 -282.405836)
		(width 0.254)
		(layer "F.Cu")
		(net "GND")
	)
	(segment
		(start 378.846334 -217.600276)
		(end 378.846334 -217.064336)
		(width 0.254)
		(layer "F.Cu")
		(net "GND")
	)
	(segment
		(start 127.616712 -237.411768)
		(end 127.616966 -237.411514)
		(width 0.254)
		(layer "F.Cu")
		(net "GND")
	)
	(segment
		(start 94.82328 -428.803308)
		(end 95.125286 -428.501302)
		(width 0.381)
		(layer "F.Cu")
		(net "GND")
	)
	(segment
		(start 134.305294 -262.058404)
		(end 134.305548 -262.058658)
		(width 0.2032)
		(layer "F.Cu")
		(net "GND")
	)
	(segment
		(start 204.076046 -203.266802)
		(end 205.180946 -203.266802)
		(width 0.381)
		(layer "F.Cu")
		(net "GND")
	)
	(segment
		(start 278.711914 -268.71676)
		(end 279.816814 -268.71676)
		(width 0.381)
		(layer "F.Cu")
		(net "GND")
	)
	(segment
		(start 414.297114 -210.916774)
		(end 415.402014 -210.916774)
		(width 0.381)
		(layer "F.Cu")
		(net "GND")
	)
	(segment
		(start 462.555082 -271.266666)
		(end 463.659982 -271.266666)
		(width 0.381)
		(layer "F.Cu")
		(net "GND")
	)
	(segment
		(start 304.338482 -295.916604)
		(end 305.443382 -295.916604)
		(width 0.381)
		(layer "F.Cu")
		(net "GND")
	)
	(segment
		(start 109.40542 -338.254848)
		(end 109.40542 -337.830668)
		(width 0.381)
		(layer "F.Cu")
		(net "GND")
	)
	(segment
		(start 348.56039 -59.543188)
		(end 348.382336 -59.721242)
		(width 0.2032)
		(layer "F.Cu")
		(net "GND")
	)
	(segment
		(start 65.047114 -210.066636)
		(end 66.367914 -210.066636)
		(width 0.381)
		(layer "F.Cu")
		(net "GND")
	)
	(segment
		(start 158.813246 -246.616728)
		(end 159.918146 -246.616728)
		(width 0.381)
		(layer "F.Cu")
		(net "GND")
	)
	(segment
		(start 101.389434 -338.366354)
		(end 101.389434 -337.856068)
		(width 0.381)
		(layer "F.Cu")
		(net "GND")
	)
	(segment
		(start 413.192214 -307.816758)
		(end 414.297114 -307.816758)
		(width 0.381)
		(layer "F.Cu")
		(net "GND")
	)
	(segment
		(start 124.907294 -278.336248)
		(end 124.907548 -278.336502)
		(width 0.254)
		(layer "F.Cu")
		(net "GND")
	)
	(segment
		(start 100.002848 -286.7533)
		(end 100.002848 -287.288986)
		(width 0.254)
		(layer "F.Cu")
		(net "GND")
	)
	(segment
		(start 11.135614 -196.466714)
		(end 12.240514 -196.466714)
		(width 0.381)
		(layer "F.Cu")
		(net "GND")
	)
	(segment
		(start 45.859446 -295.06672)
		(end 46.964346 -295.06672)
		(width 0.381)
		(layer "F.Cu")
		(net "GND")
	)
	(segment
		(start 376.606562 -259.894832)
		(end 376.606816 -260.430772)
		(width 0.2032)
		(layer "F.Cu")
		(net "GND")
	)
	(segment
		(start 94.32798 -94.899988)
		(end 94.418404 -94.899988)
		(width 0.3556)
		(layer "F.Cu")
		(net "GND")
	)
	(segment
		(start 366.15878 -232.528618)
		(end 366.159034 -232.528364)
		(width 0.2032)
		(layer "F.Cu")
		(net "GND")
	)
	(segment
		(start 59.626246 -287.416748)
		(end 60.947046 -287.416748)
		(width 0.381)
		(layer "F.Cu")
		(net "GND")
	)
	(segment
		(start 254.975614 -236.416596)
		(end 256.080514 -236.416596)
		(width 0.381)
		(layer "F.Cu")
		(net "GND")
	)
	(segment
		(start 385.534662 -260.708902)
		(end 385.19608 -260.630162)
		(width 0.254)
		(layer "F.Cu")
		(net "GND")
	)
	(segment
		(start 200.632314 -200.716642)
		(end 201.737214 -200.716642)
		(width 0.381)
		(layer "F.Cu")
		(net "GND")
	)
	(segment
		(start 373.67718 -236.319822)
		(end 373.67718 -235.783882)
		(width 0.2032)
		(layer "F.Cu")
		(net "GND")
	)
	(segment
		(start 63.942214 -211.766658)
		(end 65.047114 -211.766658)
		(width 0.381)
		(layer "F.Cu")
		(net "GND")
	)
	(segment
		(start 406.753314 -304.416714)
		(end 405.648414 -304.416714)
		(width 0.381)
		(layer "F.Cu")
		(net "GND")
	)
	(segment
		(start 377.906534 -250.155964)
		(end 377.90628 -250.15571)
		(width 0.2032)
		(layer "F.Cu")
		(net "GND")
	)
	(segment
		(start 193.088514 -271.266666)
		(end 194.193414 -271.266666)
		(width 0.381)
		(layer "F.Cu")
		(net "GND")
	)
	(segment
		(start 380.72568 -246.900192)
		(end 380.72568 -246.364506)
		(width 0.2032)
		(layer "F.Cu")
		(net "GND")
	)
	(segment
		(start 452.016114 -240.666778)
		(end 450.911214 -240.666778)
		(width 0.381)
		(layer "F.Cu")
		(net "GND")
	)
	(segment
		(start 282.811982 -198.166736)
		(end 283.916882 -198.166736)
		(width 0.381)
		(layer "F.Cu")
		(net "GND")
	)
	(segment
		(start 101.412294 -277.800562)
		(end 101.412294 -278.336502)
		(width 0.2032)
		(layer "F.Cu")
		(net "GND")
	)
	(segment
		(start 114.099848 -275.35886)
		(end 114.099848 -275.8948)
		(width 0.254)
		(layer "F.Cu")
		(net "GND")
	)
	(segment
		(start 130.91795 -156.398468)
		(end 130.30835 -156.398468)
		(width 0.3556)
		(layer "F.Cu")
		(net "GND")
	)
	(segment
		(start 340.784434 -229.808532)
		(end 340.784434 -229.272846)
		(width 0.2032)
		(layer "F.Cu")
		(net "GND")
	)
	(segment
		(start 290.355782 -267.866622)
		(end 291.460682 -267.866622)
		(width 0.381)
		(layer "F.Cu")
		(net "GND")
	)
	(segment
		(start 385.237482 -71.362824)
		(end 385.237482 -70.722998)
		(width 0.381)
		(layer "F.Cu")
		(net "GND")
	)
	(segment
		(start 349.24238 -220.041978)
		(end 349.242634 -220.041724)
		(width 0.254)
		(layer "F.Cu")
		(net "GND")
	)
	(segment
		(start 45.859446 -304.416714)
		(end 46.964346 -304.416714)
		(width 0.381)
		(layer "F.Cu")
		(net "GND")
	)
	(segment
		(start 133.365748 -281.591766)
		(end 133.365748 -281.59202)
		(width 0.254)
		(layer "F.Cu")
		(net "GND")
	)
	(segment
		(start 301.343314 -295.06672)
		(end 302.664114 -295.06672)
		(width 0.381)
		(layer "F.Cu")
		(net "GND")
	)
	(segment
		(start 32.947102 -7.215124)
		(end 32.947102 -8.320024)
		(width 0.3556)
		(layer "F.Cu")
		(net "GND")
	)
	(segment
		(start 345.123516 -267.219938)
		(end 345.123516 -267.755878)
		(width 0.2032)
		(layer "F.Cu")
		(net "GND")
	)
	(segment
		(start 157.708346 -307.816758)
		(end 158.813246 -307.816758)
		(width 0.381)
		(layer "F.Cu")
		(net "GND")
	)
	(segment
		(start 377.43638 -244.458744)
		(end 377.43638 -243.922804)
		(width 0.2032)
		(layer "F.Cu")
		(net "GND")
	)
	(segment
		(start 188.988446 -296.766742)
		(end 190.093346 -296.766742)
		(width 0.381)
		(layer "F.Cu")
		(net "GND")
	)
	(segment
		(start 153.944066 -30.941518)
		(end 154.966416 -30.941518)
		(width 0.3556)
		(layer "F.Cu")
		(net "GND")
	)
	(segment
		(start 300.238414 -309.51678)
		(end 301.343314 -309.51678)
		(width 0.381)
		(layer "F.Cu")
		(net "GND")
	)
	(segment
		(start 44.754546 -292.516814)
		(end 45.859446 -292.516814)
		(width 0.381)
		(layer "F.Cu")
		(net "GND")
	)
	(segment
		(start 289.250882 -222.816674)
		(end 290.355782 -222.816674)
		(width 0.381)
		(layer "F.Cu")
		(net "GND")
	)
	(segment
		(start 368.508534 -233.87812)
		(end 368.50828 -233.877866)
		(width 0.254)
		(layer "F.Cu")
		(net "GND")
	)
	(segment
		(start 202.971146 -206.666592)
		(end 204.076046 -206.666592)
		(width 0.381)
		(layer "F.Cu")
		(net "GND")
	)
	(segment
		(start 375.197116 -278.614378)
		(end 375.197116 -279.150064)
		(width 0.254)
		(layer "F.Cu")
		(net "GND")
	)
	(segment
		(start 166.357046 -195.616576)
		(end 167.461946 -195.616576)
		(width 0.381)
		(layer "F.Cu")
		(net "GND")
	)
	(segment
		(start 374.147334 -243.644928)
		(end 374.147334 -243.108988)
		(width 0.2032)
		(layer "F.Cu")
		(net "GND")
	)
	(segment
		(start 98.953066 -227.367084)
		(end 98.953066 -226.831144)
		(width 0.2032)
		(layer "F.Cu")
		(net "GND")
	)
	(segment
		(start 127.257048 -284.033468)
		(end 127.256794 -284.033722)
		(width 0.254)
		(layer "F.Cu")
		(net "GND")
	)
	(segment
		(start 43.520614 -267.866622)
		(end 42.415714 -267.866622)
		(width 0.381)
		(layer "F.Cu")
		(net "GND")
	)
	(segment
		(start 52.298346 -289.11677)
		(end 53.403246 -289.11677)
		(width 0.381)
		(layer "F.Cu")
		(net "GND")
	)
	(segment
		(start 421.840914 -309.51678)
		(end 420.736014 -309.51678)
		(width 0.381)
		(layer "F.Cu")
		(net "GND")
	)
	(segment
		(start 340.439248 -45.037248)
		(end 340.250272 -44.711112)
		(width 0.2032)
		(layer "F.Cu")
		(net "GND")
	)
	(segment
		(start 181.444646 -273.816572)
		(end 180.339746 -273.816572)
		(width 0.381)
		(layer "F.Cu")
		(net "GND")
	)
	(segment
		(start 373.67718 -216.78646)
		(end 373.67718 -216.250774)
		(width 0.254)
		(layer "F.Cu")
		(net "GND")
	)
	(segment
		(start 95.193612 -235.505752)
		(end 95.193612 -234.970066)
		(width 0.2032)
		(layer "F.Cu")
		(net "GND")
	)
	(segment
		(start 31.325058 -138.43762)
		(end 32.353758 -138.43762)
		(width 0.3556)
		(layer "F.Cu")
		(net "GND")
	)
	(segment
		(start 300.238414 -231.316784)
		(end 301.343314 -231.316784)
		(width 0.381)
		(layer "F.Cu")
		(net "GND")
	)
	(segment
		(start 190.093346 -214.316564)
		(end 188.988446 -214.316564)
		(width 0.381)
		(layer "F.Cu")
		(net "GND")
	)
	(segment
		(start 166.26713 -13.600176)
		(end 166.26713 -12.495022)
		(width 0.3556)
		(layer "F.Cu")
		(net "GND")
	)
	(segment
		(start 188.988446 -238.966756)
		(end 187.883546 -238.966756)
		(width 0.381)
		(layer "F.Cu")
		(net "GND")
	)
	(segment
		(start 272.273014 -251.716794)
		(end 271.168114 -251.716794)
		(width 0.381)
		(layer "F.Cu")
		(net "GND")
	)
	(segment
		(start 172.795946 -283.166566)
		(end 173.900846 -283.166566)
		(width 0.381)
		(layer "F.Cu")
		(net "GND")
	)
	(segment
		(start 174.777146 -273.816572)
		(end 173.900846 -273.816572)
		(width 0.381)
		(layer "F.Cu")
		(net "GND")
	)
	(segment
		(start 418.356796 -8.320024)
		(end 418.356796 -9.424924)
		(width 0.3556)
		(layer "F.Cu")
		(net "GND")
	)
	(segment
		(start 374.00484 -340.002622)
		(end 374.481852 -339.52561)
		(width 0.2032)
		(layer "F.Cu")
		(net "GND")
	)
	(segment
		(start 371.437916 -280.242264)
		(end 371.437662 -280.778204)
		(width 0.254)
		(layer "F.Cu")
		(net "GND")
	)
	(segment
		(start 286.255714 -304.416714)
		(end 287.360614 -304.416714)
		(width 0.381)
		(layer "F.Cu")
		(net "GND")
	)
	(segment
		(start 202.971146 -204.96657)
		(end 204.076046 -204.96657)
		(width 0.381)
		(layer "F.Cu")
		(net "GND")
	)
	(segment
		(start 343.40292 -57.45734)
		(end 342.90254 -57.605168)
		(width 0.2032)
		(layer "F.Cu")
		(net "GND")
	)
	(segment
		(start 456.116182 -235.566712)
		(end 455.011282 -235.566712)
		(width 0.381)
		(layer "F.Cu")
		(net "GND")
	)
	(segment
		(start 193.893186 -438.57418)
		(end 193.893186 -439.29808)
		(width 0.3556)
		(layer "F.Cu")
		(net "GND")
	)
	(segment
		(start 119.628666 -214.344758)
		(end 119.628666 -213.732618)
		(width 0.254)
		(layer "F.Cu")
		(net "GND")
	)
	(segment
		(start 296.794682 -289.966654)
		(end 297.899582 -289.966654)
		(width 0.381)
		(layer "F.Cu")
		(net "GND")
	)
	(segment
		(start 100.832666 -243.644928)
		(end 100.832412 -243.644674)
		(width 0.254)
		(layer "F.Cu")
		(net "GND")
	)
	(segment
		(start 361.569762 -269.66164)
		(end 361.569762 -270.19758)
		(width 0.254)
		(layer "F.Cu")
		(net "GND")
	)
	(segment
		(start 133.365494 -269.66164)
		(end 133.365494 -270.19758)
		(width 0.2032)
		(layer "F.Cu")
		(net "GND")
	)
	(segment
		(start 312.987182 -219.41663)
		(end 314.307982 -219.41663)
		(width 0.381)
		(layer "F.Cu")
		(net "GND")
	)
	(segment
		(start 365.799116 -278.614378)
		(end 365.799116 -279.150318)
		(width 0.254)
		(layer "F.Cu")
		(net "GND")
	)
	(segment
		(start 410.853382 -210.066636)
		(end 411.958282 -210.066636)
		(width 0.381)
		(layer "F.Cu")
		(net "GND")
	)
	(segment
		(start 221.48292 -50.673)
		(end 220.36786 -50.673)
		(width 0.3556)
		(layer "F.Cu")
		(net "GND")
	)
	(segment
		(start 38.315646 -229.616762)
		(end 37.210746 -229.616762)
		(width 0.381)
		(layer "F.Cu")
		(net "GND")
	)
	(segment
		(start 409.748482 -286.74441)
		(end 409.748482 -286.69361)
		(width 0.381)
		(layer "F.Cu")
		(net "GND")
	)
	(segment
		(start 48.854614 -297.616626)
		(end 49.959514 -297.616626)
		(width 0.381)
		(layer "F.Cu")
		(net "GND")
	)
	(segment
		(start 275.268182 -194.766692)
		(end 274.163282 -194.766692)
		(width 0.381)
		(layer "F.Cu")
		(net "GND")
	)
	(segment
		(start 98.123248 -271.011142)
		(end 98.122994 -271.011396)
		(width 0.2032)
		(layer "F.Cu")
		(net "GND")
	)
	(segment
		(start 378.846334 -242.017042)
		(end 378.84608 -242.016788)
		(width 0.2032)
		(layer "F.Cu")
		(net "GND")
	)
	(segment
		(start 107.521248 -281.869896)
		(end 107.521248 -282.405582)
		(width 0.254)
		(layer "F.Cu")
		(net "GND")
	)
	(segment
		(start 111.640112 -226.017582)
		(end 111.640366 -226.017328)
		(width 0.254)
		(layer "F.Cu")
		(net "GND")
	)
	(segment
		(start 132.785866 -248.528078)
		(end 132.785866 -247.992138)
		(width 0.2032)
		(layer "F.Cu")
		(net "GND")
	)
	(segment
		(start 103.652066 -227.367084)
		(end 103.652066 -226.831144)
		(width 0.254)
		(layer "F.Cu")
		(net "GND")
	)
	(segment
		(start 410.853382 -303.566576)
		(end 409.748482 -303.566576)
		(width 0.381)
		(layer "F.Cu")
		(net "GND")
	)
	(segment
		(start 131.016248 -260.708902)
		(end 131.016248 -261.244588)
		(width 0.2032)
		(layer "F.Cu")
		(net "GND")
	)
	(segment
		(start 197.637146 -298.466764)
		(end 196.532246 -298.466764)
		(width 0.381)
		(layer "F.Cu")
		(net "GND")
	)
	(segment
		(start 376.271536 -105.883202)
		(end 376.271536 -106.525568)
		(width 0.3556)
		(layer "F.Cu")
		(net "GND")
	)
	(segment
		(start 396.619476 -148.410168)
		(end 397.254476 -148.410168)
		(width 0.381)
		(layer "F.Cu")
		(net "GND")
	)
	(segment
		(start 186.649614 -275.516594)
		(end 185.544714 -275.516594)
		(width 0.381)
		(layer "F.Cu")
		(net "GND")
	)
	(segment
		(start 194.193414 -196.466714)
		(end 193.088514 -196.466714)
		(width 0.381)
		(layer "F.Cu")
		(net "GND")
	)
	(segment
		(start 210.514946 -240.666778)
		(end 211.619846 -240.666778)
		(width 0.381)
		(layer "F.Cu")
		(net "GND")
	)
	(segment
		(start 296.794682 -258.516628)
		(end 297.899582 -258.516628)
		(width 0.381)
		(layer "F.Cu")
		(net "GND")
	)
	(segment
		(start 442.171074 -124.297948)
		(end 442.171074 -124.051568)
		(width 0.381)
		(layer "F.Cu")
		(net "GND")
	)
	(segment
		(start 364.389162 -274.54479)
		(end 364.389162 -275.08073)
		(width 0.254)
		(layer "F.Cu")
		(net "GND")
	)
	(segment
		(start 311.882282 -314.616592)
		(end 312.987182 -314.616592)
		(width 0.381)
		(layer "F.Cu")
		(net "GND")
	)
	(segment
		(start 131.375912 -220.041978)
		(end 131.375912 -219.506292)
		(width 0.254)
		(layer "F.Cu")
		(net "GND")
	)
	(segment
		(start 89.554812 -232.250234)
		(end 89.554812 -231.714548)
		(width 0.2032)
		(layer "F.Cu")
		(net "GND")
	)
	(segment
		(start 362.509562 -276.708362)
		(end 362.509816 -276.708616)
		(width 0.254)
		(layer "F.Cu")
		(net "GND")
	)
	(segment
		(start 125.847094 -261.522718)
		(end 125.847094 -262.058658)
		(width 0.2032)
		(layer "F.Cu")
		(net "GND")
	)
	(segment
		(start 358.858566 -334.191102)
		(end 358.523794 -334.191102)
		(width 0.2032)
		(layer "F.Cu")
		(net "GND")
	)
	(segment
		(start 416.055302 -165.308788)
		(end 415.32048 -165.308788)
		(width 0.2032)
		(layer "F.Cu")
		(net "GND")
	)
	(segment
		(start 169.95648 -436.590948)
		(end 169.95648 -436.768748)
		(width 0.3556)
		(layer "F.Cu")
		(net "GND")
	)
	(segment
		(start 123.967494 -281.591512)
		(end 123.967748 -281.591766)
		(width 0.254)
		(layer "F.Cu")
		(net "GND")
	)
	(segment
		(start 363.046518 -360.83875)
		(end 363.656118 -360.83875)
		(width 0.381)
		(layer "F.Cu")
		(net "GND")
	)
	(segment
		(start 140.39088 -42.655998)
		(end 141.02588 -42.655998)
		(width 0.3556)
		(layer "F.Cu")
		(net "GND")
	)
	(segment
		(start 20.989798 -413.782002)
		(end 21.5138 -413.258)
		(width 0.3556)
		(layer "F.Cu")
		(net "GND")
	)
	(segment
		(start 199.527414 -258.516628)
		(end 200.632314 -258.516628)
		(width 0.381)
		(layer "F.Cu")
		(net "GND")
	)
	(segment
		(start 338.544916 -257.45313)
		(end 338.544916 -257.98907)
		(width 0.2032)
		(layer "F.Cu")
		(net "GND")
	)
	(segment
		(start 38.315646 -268.71676)
		(end 37.210746 -268.71676)
		(width 0.381)
		(layer "F.Cu")
		(net "GND")
	)
	(segment
		(start 185.544714 -288.266632)
		(end 184.439814 -288.266632)
		(width 0.381)
		(layer "F.Cu")
		(net "GND")
	)
	(segment
		(start 334.205834 -247.178322)
		(end 334.205834 -247.714262)
		(width 0.2032)
		(layer "F.Cu")
		(net "GND")
	)
	(segment
		(start 15.684246 -229.616762)
		(end 16.789146 -229.616762)
		(width 0.381)
		(layer "F.Cu")
		(net "GND")
	)
	(segment
		(start 134.305294 -263.68629)
		(end 134.305548 -263.686544)
		(width 0.2032)
		(layer "F.Cu")
		(net "GND")
	)
	(segment
		(start 386.364734 -246.900446)
		(end 387.408928 -246.900446)
		(width 0.2032)
		(layer "F.Cu")
		(net "GND")
	)
	(segment
		(start 38.315646 -231.316784)
		(end 37.210746 -231.316784)
		(width 0.381)
		(layer "F.Cu")
		(net "GND")
	)
	(segment
		(start 115.869212 -233.877866)
		(end 115.869212 -233.34218)
		(width 0.2032)
		(layer "F.Cu")
		(net "GND")
	)
	(segment
		(start 181.444646 -260.21665)
		(end 182.549546 -260.21665)
		(width 0.381)
		(layer "F.Cu")
		(net "GND")
	)
	(segment
		(start 441.028582 -295.916604)
		(end 442.133482 -295.916604)
		(width 0.381)
		(layer "F.Cu")
		(net "GND")
	)
	(segment
		(start 270.063214 -258.516628)
		(end 271.168114 -258.516628)
		(width 0.381)
		(layer "F.Cu")
		(net "GND")
	)
	(segment
		(start 436.928514 -208.366614)
		(end 438.033414 -208.366614)
		(width 0.381)
		(layer "F.Cu")
		(net "GND")
	)
	(segment
		(start 385.070858 -253.919736)
		(end 385.064762 -253.919736)
		(width 0.2032)
		(layer "F.Cu")
		(net "GND")
	)
	(segment
		(start 254.975614 -311.216802)
		(end 256.080514 -311.216802)
		(width 0.381)
		(layer "F.Cu")
		(net "GND")
	)
	(segment
		(start 133.365494 -264.778236)
		(end 133.365494 -265.314176)
		(width 0.2032)
		(layer "F.Cu")
		(net "GND")
	)
	(segment
		(start 215.719914 -275.516594)
		(end 216.824814 -275.516594)
		(width 0.381)
		(layer "F.Cu")
		(net "GND")
	)
	(segment
		(start 27.328114 -224.516696)
		(end 28.433014 -224.516696)
		(width 0.381)
		(layer "F.Cu")
		(net "GND")
	)
	(segment
		(start 150.85695 -13.600176)
		(end 150.85695 -12.495022)
		(width 0.3556)
		(layer "F.Cu")
		(net "GND")
	)
	(segment
		(start 349.352362 -276.172676)
		(end 349.352362 -276.708362)
		(width 0.254)
		(layer "F.Cu")
		(net "GND")
	)
	(segment
		(start 411.958282 -233.86669)
		(end 410.853382 -233.86669)
		(width 0.381)
		(layer "F.Cu")
		(net "GND")
	)
	(segment
		(start 100.832666 -217.600276)
		(end 100.832666 -217.064336)
		(width 0.2032)
		(layer "F.Cu")
		(net "GND")
	)
	(segment
		(start 371.327934 -224.111566)
		(end 371.327934 -223.575626)
		(width 0.2032)
		(layer "F.Cu")
		(net "GND")
	)
	(segment
		(start 416.484562 -182.151528)
		(end 416.056572 -182.579518)
		(width 0.2032)
		(layer "F.Cu")
		(net "GND")
	)
	(segment
		(start 337.604862 -279.150064)
		(end 337.604862 -279.150318)
		(width 0.2032)
		(layer "F.Cu")
		(net "GND")
	)
	(segment
		(start 180.555646 -114.575336)
		(end 180.955696 -114.975386)
		(width 0.3556)
		(layer "F.Cu")
		(net "GND")
	)
	(segment
		(start 162.913314 -205.816708)
		(end 161.600134 -205.816708)
		(width 0.381)
		(layer "F.Cu")
		(net "GND")
	)
	(segment
		(start 86.375494 -282.683966)
		(end 86.375494 -283.219906)
		(width 0.2032)
		(layer "F.Cu")
		(net "GND")
	)
	(segment
		(start 406.753314 -217.716608)
		(end 408.082242 -217.716608)
		(width 0.381)
		(layer "F.Cu")
		(net "GND")
	)
	(segment
		(start 346.063062 -265.592306)
		(end 346.063062 -266.128246)
		(width 0.254)
		(layer "F.Cu")
		(net "GND")
	)
	(segment
		(start 48.854614 -239.81664)
		(end 49.959514 -239.81664)
		(width 0.381)
		(layer "F.Cu")
		(net "GND")
	)
	(segment
		(start 334.099408 -49.650396)
		(end 334.097376 -49.649888)
		(width 0.2032)
		(layer "F.Cu")
		(net "GND")
	)
	(segment
		(start 341.37727 -46.570646)
		(end 341.105998 -46.100746)
		(width 0.2032)
		(layer "F.Cu")
		(net "GND")
	)
	(segment
		(start 421.840914 -290.816792)
		(end 420.736014 -290.816792)
		(width 0.381)
		(layer "F.Cu")
		(net "GND")
	)
	(segment
		(start 365.60125 -411.5562)
		(end 366.2172 -411.5562)
		(width 0.3556)
		(layer "F.Cu")
		(net "GND")
	)
	(segment
		(start 340.78418 -249.342148)
		(end 340.784434 -249.341894)
		(width 0.2032)
		(layer "F.Cu")
		(net "GND")
	)
	(segment
		(start 419.74643 -207.51673)
		(end 418.397182 -207.51673)
		(width 0.381)
		(layer "F.Cu")
		(net "GND")
	)
	(segment
		(start 406.753314 -290.816792)
		(end 407.858214 -290.816792)
		(width 0.381)
		(layer "F.Cu")
		(net "GND")
	)
	(segment
		(start 195.427346 -201.56678)
		(end 196.532246 -201.56678)
		(width 0.381)
		(layer "F.Cu")
		(net "GND")
	)
	(segment
		(start 124.327412 -235.505752)
		(end 124.327412 -234.970066)
		(width 0.2032)
		(layer "F.Cu")
		(net "GND")
	)
	(segment
		(start 340.894162 -264.778236)
		(end 340.894162 -265.313922)
		(width 0.2032)
		(layer "F.Cu")
		(net "GND")
	)
	(segment
		(start 328.244962 -40.686228)
		(end 328.188828 -40.630094)
		(width 0.2032)
		(layer "F.Cu")
		(net "GND")
	)
	(segment
		(start 352.531934 -227.367084)
		(end 352.531934 -226.831144)
		(width 0.254)
		(layer "F.Cu")
		(net "GND")
	)
	(segment
		(start 337.29168 -21.442172)
		(end 337.142328 -21.29282)
		(width 0.3556)
		(layer "F.Cu")
		(net "GND")
	)
	(segment
		(start 131.016248 -273.730974)
		(end 131.015994 -274.266914)
		(width 0.2032)
		(layer "F.Cu")
		(net "GND")
	)
	(segment
		(start 133.027674 -365.05007)
		(end 133.725412 -365.747808)
		(width 0.508)
		(layer "F.Cu")
		(net "GND")
	)
	(segment
		(start 328.434446 -39.756588)
		(end 328.895964 -39.295324)
		(width 0.2032)
		(layer "F.Cu")
		(net "GND")
	)
	(segment
		(start 27.328114 -194.766692)
		(end 28.433014 -194.766692)
		(width 0.381)
		(layer "F.Cu")
		(net "GND")
	)
	(segment
		(start 18.679414 -266.1666)
		(end 19.784314 -266.1666)
		(width 0.381)
		(layer "F.Cu")
		(net "GND")
	)
	(segment
		(start 351.231962 -281.05608)
		(end 351.231962 -281.59202)
		(width 0.2032)
		(layer "F.Cu")
		(net "GND")
	)
	(segment
		(start 276.373082 -216.866724)
		(end 275.268182 -216.866724)
		(width 0.381)
		(layer "F.Cu")
		(net "GND")
	)
	(segment
		(start 262.519414 -203.266802)
		(end 263.624314 -203.266802)
		(width 0.381)
		(layer "F.Cu")
		(net "GND")
	)
	(segment
		(start 199.527414 -310.366664)
		(end 200.632314 -310.366664)
		(width 0.381)
		(layer "F.Cu")
		(net "GND")
	)
	(segment
		(start 22.123146 -272.116804)
		(end 23.228046 -272.116804)
		(width 0.381)
		(layer "F.Cu")
		(net "GND")
	)
	(segment
		(start 441.353194 -30.64002)
		(end 441.353194 -29.575506)
		(width 0.254)
		(layer "F.Cu")
		(net "GND")
	)
	(segment
		(start 337.965034 -220.041724)
		(end 337.965034 -219.506038)
		(width 0.254)
		(layer "F.Cu")
		(net "GND")
	)
	(segment
		(start 297.899582 -228.766624)
		(end 299.004482 -228.766624)
		(width 0.381)
		(layer "F.Cu")
		(net "GND")
	)
	(segment
		(start 261.285482 -230.466646)
		(end 260.180582 -230.466646)
		(width 0.381)
		(layer "F.Cu")
		(net "GND")
	)
	(segment
		(start 423.61866 -51.00828)
		(end 422.82364 -51.00828)
		(width 0.3556)
		(layer "F.Cu")
		(net "GND")
	)
	(segment
		(start 406.753314 -231.316784)
		(end 407.858214 -231.316784)
		(width 0.381)
		(layer "F.Cu")
		(net "GND")
	)
	(segment
		(start 29.666946 -307.816758)
		(end 30.771846 -307.816758)
		(width 0.381)
		(layer "F.Cu")
		(net "GND")
	)
	(segment
		(start 312.987182 -235.566712)
		(end 314.307982 -235.566712)
		(width 0.381)
		(layer "F.Cu")
		(net "GND")
	)
	(segment
		(start 419.502082 -277.216616)
		(end 418.397182 -277.216616)
		(width 0.381)
		(layer "F.Cu")
		(net "GND")
	)
	(segment
		(start 434.805328 -20.6375)
		(end 434.805328 -20.014184)
		(width 0.3556)
		(layer "F.Cu")
		(net "GND")
	)
	(segment
		(start 378.956316 -275.35886)
		(end 378.956062 -275.8948)
		(width 0.2032)
		(layer "F.Cu")
		(net "GND")
	)
	(segment
		(start 45.75683 -335.477612)
		(end 46.697138 -335.477612)
		(width 0.508)
		(layer "F.Cu")
		(net "GND")
	)
	(segment
		(start 127.726694 -257.175254)
		(end 127.726694 -256.639314)
		(width 0.2032)
		(layer "F.Cu")
		(net "GND")
	)
	(segment
		(start 214.615014 -308.666642)
		(end 215.719914 -308.666642)
		(width 0.381)
		(layer "F.Cu")
		(net "GND")
	)
	(segment
		(start 436.928514 -290.816792)
		(end 438.033414 -290.816792)
		(width 0.381)
		(layer "F.Cu")
		(net "GND")
	)
	(segment
		(start 344.073734 -243.644928)
		(end 344.07348 -243.644674)
		(width 0.2032)
		(layer "F.Cu")
		(net "GND")
	)
	(segment
		(start 116.339112 -216.250774)
		(end 116.339366 -216.25052)
		(width 0.254)
		(layer "F.Cu")
		(net "GND")
	)
	(segment
		(start 396.646908 -11.26998)
		(end 396.646908 -12.37488)
		(width 0.3556)
		(layer "F.Cu")
		(net "GND")
	)
	(segment
		(start 411.958282 -194.766692)
		(end 410.853382 -194.766692)
		(width 0.381)
		(layer "F.Cu")
		(net "GND")
	)
	(segment
		(start 129.496312 -216.250774)
		(end 129.496566 -216.25052)
		(width 0.254)
		(layer "F.Cu")
		(net "GND")
	)
	(segment
		(start 327.137522 -59.371992)
		(end 327.218548 -58.771028)
		(width 0.2032)
		(layer "F.Cu")
		(net "GND")
	)
	(segment
		(start 178.000914 -294.216582)
		(end 179.105814 -294.216582)
		(width 0.381)
		(layer "F.Cu")
		(net "GND")
	)
	(segment
		(start 419.502082 -213.46668)
		(end 418.397182 -213.46668)
		(width 0.381)
		(layer "F.Cu")
		(net "GND")
	)
	(segment
		(start 410.853382 -198.166736)
		(end 411.958282 -198.166736)
		(width 0.381)
		(layer "F.Cu")
		(net "GND")
	)
	(segment
		(start 66.94932 -56.140858)
		(end 66.94932 -55.531258)
		(width 0.3556)
		(layer "F.Cu")
		(net "GND")
	)
	(segment
		(start 308.887114 -210.916774)
		(end 309.992014 -210.916774)
		(width 0.381)
		(layer "F.Cu")
		(net "GND")
	)
	(segment
		(start 271.168114 -225.36658)
		(end 272.273014 -225.36658)
		(width 0.381)
		(layer "F.Cu")
		(net "GND")
	)
	(segment
		(start 432.379882 -226.216718)
		(end 433.484782 -226.216718)
		(width 0.381)
		(layer "F.Cu")
		(net "GND")
	)
	(segment
		(start 332.796134 -233.87812)
		(end 332.326234 -234.15625)
		(width 0.2032)
		(layer "F.Cu")
		(net "GND")
	)
	(segment
		(start 35.976814 -291.666676)
		(end 34.871914 -291.666676)
		(width 0.381)
		(layer "F.Cu")
		(net "GND")
	)
	(segment
		(start 193.088514 -213.46668)
		(end 191.983614 -213.46668)
		(width 0.381)
		(layer "F.Cu")
		(net "GND")
	)
	(segment
		(start 158.9532 -79.225648)
		(end 158.897574 -79.170022)
		(width 0.3556)
		(layer "F.Cu")
		(net "GND")
	)
	(segment
		(start 378.956316 -256.361184)
		(end 378.956062 -256.361438)
		(width 0.254)
		(layer "F.Cu")
		(net "GND")
	)
	(segment
		(start 379.31598 -216.78646)
		(end 379.31598 -216.250774)
		(width 0.254)
		(layer "F.Cu")
		(net "GND")
	)
	(segment
		(start 429.384714 -304.416714)
		(end 430.489614 -304.416714)
		(width 0.381)
		(layer "F.Cu")
		(net "GND")
	)
	(segment
		(start 172.795946 -285.716726)
		(end 173.900846 -285.716726)
		(width 0.381)
		(layer "F.Cu")
		(net "GND")
	)
	(segment
		(start 351.12198 -223.297496)
		(end 351.12198 -222.76181)
		(width 0.254)
		(layer "F.Cu")
		(net "GND")
	)
	(segment
		(start 373.207534 -220.855794)
		(end 373.207534 -220.319854)
		(width 0.2032)
		(layer "F.Cu")
		(net "GND")
	)
	(segment
		(start 386.364734 -219.228162)
		(end 386.364734 -218.692222)
		(width 0.254)
		(layer "F.Cu")
		(net "GND")
	)
	(segment
		(start 63.726314 -207.51673)
		(end 65.047114 -207.51673)
		(width 0.381)
		(layer "F.Cu")
		(net "GND")
	)
	(segment
		(start 15.684246 -272.116804)
		(end 16.789146 -272.116804)
		(width 0.381)
		(layer "F.Cu")
		(net "GND")
	)
	(segment
		(start 301.343314 -289.11677)
		(end 302.448214 -289.11677)
		(width 0.381)
		(layer "F.Cu")
		(net "GND")
	)
	(segment
		(start 215.719914 -204.116686)
		(end 216.824814 -204.116686)
		(width 0.381)
		(layer "F.Cu")
		(net "GND")
	)
	(segment
		(start 12.240514 -306.96662)
		(end 13.345414 -306.96662)
		(width 0.381)
		(layer "F.Cu")
		(net "GND")
	)
	(segment
		(start 91.074494 -266.941808)
		(end 91.074494 -266.405868)
		(width 0.2032)
		(layer "F.Cu")
		(net "GND")
	)
	(segment
		(start 266.619482 -244.066568)
		(end 267.724382 -244.066568)
		(width 0.381)
		(layer "F.Cu")
		(net "GND")
	)
	(segment
		(start 107.880912 -216.78646)
		(end 107.880912 -216.250774)
		(width 0.254)
		(layer "F.Cu")
		(net "GND")
	)
	(segment
		(start 109.832648 -336.592418)
		(end 109.744002 -336.592418)
		(width 0.254)
		(layer "F.Cu")
		(net "GND")
	)
	(segment
		(start 358.280716 -267.219938)
		(end 358.280716 -267.755624)
		(width 0.254)
		(layer "F.Cu")
		(net "GND")
	)
	(segment
		(start 184.855612 -410.083762)
		(end 184.246012 -410.083762)
		(width 0.3556)
		(layer "F.Cu")
		(net "GND")
	)
	(segment
		(start 411.958282 -297.616626)
		(end 410.853382 -297.616626)
		(width 0.381)
		(layer "F.Cu")
		(net "GND")
	)
	(segment
		(start 411.35681 -29.879036)
		(end 411.450028 -29.785818)
		(width 0.3556)
		(layer "F.Cu")
		(net "GND")
	)
	(segment
		(start 420.736014 -251.716794)
		(end 421.840914 -251.716794)
		(width 0.381)
		(layer "F.Cu")
		(net "GND")
	)
	(segment
		(start 95.17126 -414.4518)
		(end 95.1484 -414.42894)
		(width 0.3556)
		(layer "F.Cu")
		(net "GND")
	)
	(segment
		(start 261.285482 -267.866622)
		(end 260.180582 -267.866622)
		(width 0.381)
		(layer "F.Cu")
		(net "GND")
	)
	(segment
		(start 349.24238 -244.458744)
		(end 349.24238 -243.922804)
		(width 0.2032)
		(layer "F.Cu")
		(net "GND")
	)
	(segment
		(start 58.481214 -239.81664)
		(end 57.503314 -239.81664)
		(width 0.381)
		(layer "F.Cu")
		(net "GND")
	)
	(segment
		(start 359.580434 -228.180646)
		(end 359.580434 -227.64496)
		(width 0.2032)
		(layer "F.Cu")
		(net "GND")
	)
	(segment
		(start 170.457114 -200.716642)
		(end 169.352214 -200.716642)
		(width 0.381)
		(layer "F.Cu")
		(net "GND")
	)
	(segment
		(start 39.420546 -229.616762)
		(end 38.315646 -229.616762)
		(width 0.381)
		(layer "F.Cu")
		(net "GND")
	)
	(segment
		(start 464.764882 -280.61666)
		(end 463.659982 -280.61666)
		(width 0.381)
		(layer "F.Cu")
		(net "GND")
	)
	(segment
		(start 80.066134 -347.930978)
		(end 80.066134 -348.60103)
		(width 0.381)
		(layer "F.Cu")
		(net "GND")
	)
	(segment
		(start 357.70058 -215.158574)
		(end 357.70058 -214.622888)
		(width 0.1778)
		(layer "F.Cu")
		(net "GND")
	)
	(segment
		(start 414.297114 -250.016772)
		(end 415.402014 -250.016772)
		(width 0.381)
		(layer "F.Cu")
		(net "GND")
	)
	(segment
		(start 326.913494 -45.535088)
		(end 326.999854 -45.448728)
		(width 0.2032)
		(layer "F.Cu")
		(net "GND")
	)
	(segment
		(start 373.67718 -220.041978)
		(end 373.677434 -220.041724)
		(width 0.254)
		(layer "F.Cu")
		(net "GND")
	)
	(segment
		(start 376.49658 -232.528618)
		(end 376.496834 -232.528364)
		(width 0.254)
		(layer "F.Cu")
		(net "GND")
	)
	(segment
		(start 271.168114 -221.96679)
		(end 270.063214 -221.96679)
		(width 0.381)
		(layer "F.Cu")
		(net "GND")
	)
	(segment
		(start 348.382336 -59.721242)
		(end 346.359988 -59.721242)
		(width 0.2032)
		(layer "F.Cu")
		(net "GND")
	)
	(segment
		(start 128.556512 -222.76181)
		(end 128.556766 -222.761556)
		(width 0.254)
		(layer "F.Cu")
		(net "GND")
	)
	(segment
		(start 457.221082 -202.416664)
		(end 456.116182 -202.416664)
		(width 0.381)
		(layer "F.Cu")
		(net "GND")
	)
	(segment
		(start 34.871914 -264.466578)
		(end 35.976814 -264.466578)
		(width 0.381)
		(layer "F.Cu")
		(net "GND")
	)
	(segment
		(start 129.026666 -232.250488)
		(end 129.026666 -231.714548)
		(width 0.2032)
		(layer "F.Cu")
		(net "GND")
	)
	(segment
		(start 30.771846 -315.46673)
		(end 31.876746 -315.46673)
		(width 0.381)
		(layer "F.Cu")
		(net "GND")
	)
	(segment
		(start 414.297114 -199.01662)
		(end 415.402014 -199.01662)
		(width 0.381)
		(layer "F.Cu")
		(net "GND")
	)
	(segment
		(start 43.520614 -289.966654)
		(end 42.415714 -289.966654)
		(width 0.381)
		(layer "F.Cu")
		(net "GND")
	)
	(segment
		(start 375.55678 -236.319822)
		(end 375.557034 -236.319568)
		(width 0.2032)
		(layer "F.Cu")
		(net "GND")
	)
	(segment
		(start 101.882448 -284.033468)
		(end 101.882194 -284.033722)
		(width 0.254)
		(layer "F.Cu")
		(net "GND")
	)
	(segment
		(start 250.490228 -91.358974)
		(end 249.786394 -90.65514)
		(width 0.3556)
		(layer "F.Cu")
		(net "GND")
	)
	(segment
		(start 370.967762 -258.2672)
		(end 370.967762 -258.80314)
		(width 0.254)
		(layer "F.Cu")
		(net "GND")
	)
	(segment
		(start 50.145442 -152.779984)
		(end 50.360834 -152.564592)
		(width 0.381)
		(layer "F.Cu")
		(net "GND")
	)
	(segment
		(start 12.240514 -200.716642)
		(end 11.135614 -200.716642)
		(width 0.381)
		(layer "F.Cu")
		(net "GND")
	)
	(segment
		(start 162.913314 -282.316682)
		(end 164.018214 -282.316682)
		(width 0.381)
		(layer "F.Cu")
		(net "GND")
	)
	(segment
		(start 457.994766 -92.022422)
		(end 458.487526 -92.515182)
		(width 0.3556)
		(layer "F.Cu")
		(net "GND")
	)
	(segment
		(start 11.135614 -271.266666)
		(end 12.240514 -271.266666)
		(width 0.381)
		(layer "F.Cu")
		(net "GND")
	)
	(segment
		(start 14.579346 -298.466764)
		(end 15.684246 -298.466764)
		(width 0.381)
		(layer "F.Cu")
		(net "GND")
	)
	(segment
		(start 278.711914 -231.316784)
		(end 279.816814 -231.316784)
		(width 0.381)
		(layer "F.Cu")
		(net "GND")
	)
	(segment
		(start 124.797312 -216.250774)
		(end 124.797566 -216.25052)
		(width 0.254)
		(layer "F.Cu")
		(net "GND")
	)
	(segment
		(start 256.080514 -307.816758)
		(end 257.185414 -307.816758)
		(width 0.381)
		(layer "F.Cu")
		(net "GND")
	)
	(segment
		(start 28.638246 -396.390876)
		(end 28.028646 -396.390876)
		(width 0.3556)
		(layer "F.Cu")
		(net "GND")
	)
	(segment
		(start 333.26578 -237.947454)
		(end 333.26578 -237.411768)
		(width 0.254)
		(layer "F.Cu")
		(net "GND")
	)
	(segment
		(start 261.285482 -282.316682)
		(end 260.180582 -282.316682)
		(width 0.381)
		(layer "F.Cu")
		(net "GND")
	)
	(segment
		(start 42.057066 -7.215124)
		(end 42.057066 -8.320024)
		(width 0.3556)
		(layer "F.Cu")
		(net "GND")
	)
	(segment
		(start 124.327412 -243.644674)
		(end 124.327412 -243.108988)
		(width 0.2032)
		(layer "F.Cu")
		(net "GND")
	)
	(segment
		(start 357.23068 -238.76127)
		(end 357.23068 -238.225584)
		(width 0.254)
		(layer "F.Cu")
		(net "GND")
	)
	(segment
		(start 381.19558 -247.714262)
		(end 381.19558 -247.178322)
		(width 0.2032)
		(layer "F.Cu")
		(net "GND")
	)
	(segment
		(start 15.055088 -336.821272)
		(end 14.040358 -336.821272)
		(width 0.381)
		(layer "F.Cu")
		(net "GND")
	)
	(segment
		(start 42.415714 -275.516594)
		(end 41.310814 -275.516594)
		(width 0.381)
		(layer "F.Cu")
		(net "GND")
	)
	(segment
		(start 123.360942 -100.407978)
		(end 123.360942 -97.13087)
		(width 0.254)
		(layer "F.Cu")
		(net "GND")
	)
	(segment
		(start 59.842146 -201.56678)
		(end 60.947046 -201.56678)
		(width 0.381)
		(layer "F.Cu")
		(net "GND")
	)
	(segment
		(start 447.467482 -278.916638)
		(end 448.572382 -278.916638)
		(width 0.381)
		(layer "F.Cu")
		(net "GND")
	)
	(segment
		(start 339.484716 -259.081016)
		(end 339.484716 -259.616956)
		(width 0.2032)
		(layer "F.Cu")
		(net "GND")
	)
	(segment
		(start 185.544714 -267.866622)
		(end 186.649614 -267.866622)
		(width 0.381)
		(layer "F.Cu")
		(net "GND")
	)
	(segment
		(start 362.979716 -268.84757)
		(end 362.979462 -269.38351)
		(width 0.2032)
		(layer "F.Cu")
		(net "GND")
	)
	(segment
		(start 59.918346 -221.96679)
		(end 60.947046 -221.96679)
		(width 0.381)
		(layer "F.Cu")
		(net "GND")
	)
	(segment
		(start 170.457114 -230.466646)
		(end 169.352214 -230.466646)
		(width 0.381)
		(layer "F.Cu")
		(net "GND")
	)
	(segment
		(start 407.446988 -8.320024)
		(end 407.446988 -9.424924)
		(width 0.3556)
		(layer "F.Cu")
		(net "GND")
	)
	(segment
		(start 92.459556 -97.105216)
		(end 92.967048 -97.105216)
		(width 0.3556)
		(layer "F.Cu")
		(net "GND")
	)
	(segment
		(start 350.18218 -226.553268)
		(end 350.18218 -226.017582)
		(width 0.254)
		(layer "F.Cu")
		(net "GND")
	)
	(segment
		(start 376.606816 -270.167862)
		(end 376.606816 -270.19758)
		(width 0.2032)
		(layer "F.Cu")
		(net "GND")
	)
	(segment
		(start 91.434666 -233.87812)
		(end 91.434666 -233.34218)
		(width 0.2032)
		(layer "F.Cu")
		(net "GND")
	)
	(segment
		(start 120.098312 -222.76181)
		(end 120.098566 -222.761556)
		(width 0.254)
		(layer "F.Cu")
		(net "GND")
	)
	(segment
		(start 372.847362 -281.05608)
		(end 372.847362 -281.591512)
		(width 0.254)
		(layer "F.Cu")
		(net "GND")
	)
	(segment
		(start 130.906266 -246.900446)
		(end 130.906012 -246.900192)
		(width 0.2032)
		(layer "F.Cu")
		(net "GND")
	)
	(segment
		(start 194.193414 -198.166736)
		(end 193.088514 -198.166736)
		(width 0.381)
		(layer "F.Cu")
		(net "GND")
	)
	(segment
		(start 102.352094 -285.939484)
		(end 102.352094 -286.475424)
		(width 0.2032)
		(layer "F.Cu")
		(net "GND")
	)
	(segment
		(start 128.556766 -237.947454)
		(end 128.556766 -237.411514)
		(width 0.254)
		(layer "F.Cu")
		(net "GND")
	)
	(segment
		(start 441.028582 -224.516696)
		(end 442.133482 -224.516696)
		(width 0.381)
		(layer "F.Cu")
		(net "GND")
	)
	(segment
		(start 135.714994 -263.96442)
		(end 135.714994 -264.50036)
		(width 0.254)
		(layer "F.Cu")
		(net "GND")
	)
	(segment
		(start 341.37727 -56.908446)
		(end 341.105998 -56.438546)
		(width 0.254)
		(layer "F.Cu")
		(net "GND")
	)
	(segment
		(start 121.148094 -279.428194)
		(end 121.148348 -279.964134)
		(width 0.254)
		(layer "F.Cu")
		(net "GND")
	)
	(segment
		(start 111.170466 -238.761524)
		(end 111.170466 -238.225838)
		(width 0.254)
		(layer "F.Cu")
		(net "GND")
	)
	(segment
		(start 27.328114 -291.666676)
		(end 28.433014 -291.666676)
		(width 0.381)
		(layer "F.Cu")
		(net "GND")
	)
	(segment
		(start 439.923682 -202.416664)
		(end 441.028582 -202.416664)
		(width 0.381)
		(layer "F.Cu")
		(net "GND")
	)
	(segment
		(start 107.880912 -220.041978)
		(end 107.881166 -220.041724)
		(width 0.254)
		(layer "F.Cu")
		(net "GND")
	)
	(segment
		(start 44.754546 -238.966756)
		(end 45.859446 -238.966756)
		(width 0.381)
		(layer "F.Cu")
		(net "GND")
	)
	(segment
		(start 452.016114 -295.06672)
		(end 450.911214 -295.06672)
		(width 0.381)
		(layer "F.Cu")
		(net "GND")
	)
	(segment
		(start 54.807358 -153.35631)
		(end 55.436262 -153.35631)
		(width 0.2032)
		(layer "F.Cu")
		(net "GND")
	)
	(segment
		(start 444.472314 -301.866808)
		(end 445.577214 -301.866808)
		(width 0.381)
		(layer "F.Cu")
		(net "GND")
	)
	(segment
		(start 379.425962 -277.800562)
		(end 379.426216 -278.336502)
		(width 0.2032)
		(layer "F.Cu")
		(net "GND")
	)
	(segment
		(start 92.954094 -273.452844)
		(end 92.954348 -273.453098)
		(width 0.2032)
		(layer "F.Cu")
		(net "GND")
	)
	(segment
		(start 39.420546 -204.96657)
		(end 38.315646 -204.96657)
		(width 0.381)
		(layer "F.Cu")
		(net "GND")
	)
	(segment
		(start 113.989866 -223.575626)
		(end 113.989866 -224.111566)
		(width 0.2032)
		(layer "F.Cu")
		(net "GND")
	)
	(segment
		(start 196.532246 -227.066602)
		(end 195.427346 -227.066602)
		(width 0.381)
		(layer "F.Cu")
		(net "GND")
	)
	(segment
		(start 387.417564 -254.197612)
		(end 387.450584 -254.164592)
		(width 0.2032)
		(layer "F.Cu")
		(net "GND")
	)
	(segment
		(start 166.357046 -272.116804)
		(end 167.461946 -272.116804)
		(width 0.381)
		(layer "F.Cu")
		(net "GND")
	)
	(segment
		(start 421.396414 -153.510742)
		(end 421.30472 -153.419048)
		(width 0.254)
		(layer "F.Cu")
		(net "GND")
	)
	(segment
		(start 91.544394 -266.128246)
		(end 91.544394 -265.592306)
		(width 0.254)
		(layer "F.Cu")
		(net "GND")
	)
	(segment
		(start 95.303848 -267.219938)
		(end 95.303594 -267.220192)
		(width 0.2032)
		(layer "F.Cu")
		(net "GND")
	)
	(segment
		(start 449.677282 -306.96662)
		(end 448.572382 -306.96662)
		(width 0.381)
		(layer "F.Cu")
		(net "GND")
	)
	(segment
		(start 439.923682 -215.166702)
		(end 441.028582 -215.166702)
		(width 0.381)
		(layer "F.Cu")
		(net "GND")
	)
	(segment
		(start 360.050334 -215.972644)
		(end 360.050334 -215.436958)
		(width 0.2032)
		(layer "F.Cu")
		(net "GND")
	)
	(segment
		(start 43.520614 -198.166736)
		(end 42.415714 -198.166736)
		(width 0.381)
		(layer "F.Cu")
		(net "GND")
	)
	(segment
		(start 346.532962 -279.428194)
		(end 346.532962 -279.96388)
		(width 0.254)
		(layer "F.Cu")
		(net "GND")
	)
	(segment
		(start 243.72189 -251.581158)
		(end 244.37467 -251.581158)
		(width 0.3556)
		(layer "F.Cu")
		(net "GND")
	)
	(segment
		(start 382.135634 -226.017328)
		(end 382.135634 -226.553268)
		(width 0.254)
		(layer "F.Cu")
		(net "GND")
	)
	(segment
		(start 354.991162 -281.05608)
		(end 354.991162 -281.591766)
		(width 0.254)
		(layer "F.Cu")
		(net "GND")
	)
	(segment
		(start 97.543366 -234.691936)
		(end 97.543366 -234.15625)
		(width 0.254)
		(layer "F.Cu")
		(net "GND")
	)
	(segment
		(start 413.192214 -270.416782)
		(end 414.297114 -270.416782)
		(width 0.381)
		(layer "F.Cu")
		(net "GND")
	)
	(segment
		(start 340.318598 -44.642786)
		(end 340.562946 -44.221146)
		(width 0.2032)
		(layer "F.Cu")
		(net "GND")
	)
	(segment
		(start 432.757072 -176.671478)
		(end 432.81473 -176.61382)
		(width 0.254)
		(layer "F.Cu")
		(net "GND")
	)
	(segment
		(start 281.707082 -288.266632)
		(end 282.811982 -288.266632)
		(width 0.381)
		(layer "F.Cu")
		(net "GND")
	)
	(segment
		(start 330.492354 -57.2643)
		(end 330.896976 -57.605168)
		(width 0.2032)
		(layer "F.Cu")
		(net "GND")
	)
	(segment
		(start 448.572382 -288.266632)
		(end 447.467482 -288.266632)
		(width 0.381)
		(layer "F.Cu")
		(net "GND")
	)
	(segment
		(start 371.907816 -281.591766)
		(end 371.907816 -281.59202)
		(width 0.254)
		(layer "F.Cu")
		(net "GND")
	)
	(segment
		(start 456.116182 -282.316682)
		(end 455.011282 -282.316682)
		(width 0.381)
		(layer "F.Cu")
		(net "GND")
	)
	(segment
		(start 375.55678 -216.250774)
		(end 375.557034 -216.25052)
		(width 0.254)
		(layer "F.Cu")
		(net "GND")
	)
	(segment
		(start 181.444646 -270.416782)
		(end 182.549546 -270.416782)
		(width 0.381)
		(layer "F.Cu")
		(net "GND")
	)
	(segment
		(start 89.194894 -255.011682)
		(end 89.195148 -255.547622)
		(width 0.2032)
		(layer "F.Cu")
		(net "GND")
	)
	(segment
		(start 162.913314 -200.716642)
		(end 164.018214 -200.716642)
		(width 0.381)
		(layer "F.Cu")
		(net "GND")
	)
	(segment
		(start 312.987182 -271.266666)
		(end 314.307982 -271.266666)
		(width 0.381)
		(layer "F.Cu")
		(net "GND")
	)
	(segment
		(start 199.527414 -221.116652)
		(end 200.632314 -221.116652)
		(width 0.381)
		(layer "F.Cu")
		(net "GND")
	)
	(segment
		(start 35.976814 -284.866588)
		(end 34.871914 -284.866588)
		(width 0.381)
		(layer "F.Cu")
		(net "GND")
	)
	(segment
		(start 110.340648 -280.77795)
		(end 110.340394 -280.778204)
		(width 0.254)
		(layer "F.Cu")
		(net "GND")
	)
	(segment
		(start 23.228046 -295.06672)
		(end 24.332946 -295.06672)
		(width 0.381)
		(layer "F.Cu")
		(net "GND")
	)
	(segment
		(start 327.240138 -38.2905)
		(end 326.584818 -38.2905)
		(width 0.2032)
		(layer "F.Cu")
		(net "GND")
	)
	(segment
		(start 166.357046 -313.766708)
		(end 167.699436 -313.766708)
		(width 0.381)
		(layer "F.Cu")
		(net "GND")
	)
	(segment
		(start 365.21898 -220.041978)
		(end 365.219234 -220.041724)
		(width 0.254)
		(layer "F.Cu")
		(net "GND")
	)
	(segment
		(start 282.811982 -312.91657)
		(end 283.916882 -312.91657)
		(width 0.381)
		(layer "F.Cu")
		(net "GND")
	)
	(segment
		(start 311.666382 -216.866724)
		(end 312.987182 -216.866724)
		(width 0.381)
		(layer "F.Cu")
		(net "GND")
	)
	(segment
		(start 127.616712 -222.76181)
		(end 127.616966 -222.761556)
		(width 0.254)
		(layer "F.Cu")
		(net "GND")
	)
	(segment
		(start 444.472314 -260.21665)
		(end 443.367414 -260.21665)
		(width 0.381)
		(layer "F.Cu")
		(net "GND")
	)
	(segment
		(start 49.959514 -238.116618)
		(end 51.064414 -238.116618)
		(width 0.381)
		(layer "F.Cu")
		(net "GND")
	)
	(segment
		(start 439.923682 -295.916604)
		(end 441.028582 -295.916604)
		(width 0.381)
		(layer "F.Cu")
		(net "GND")
	)
	(segment
		(start 88.145366 -230.900478)
		(end 88.145366 -231.436418)
		(width 0.254)
		(layer "F.Cu")
		(net "GND")
	)
	(segment
		(start 126.317248 -259.081016)
		(end 126.317248 -259.093462)
		(width 0.2032)
		(layer "F.Cu")
		(net "GND")
	)
	(segment
		(start 278.711914 -216.016586)
		(end 279.816814 -216.016586)
		(width 0.381)
		(layer "F.Cu")
		(net "GND")
	)
	(segment
		(start 300.238414 -216.016586)
		(end 301.343314 -216.016586)
		(width 0.381)
		(layer "F.Cu")
		(net "GND")
	)
	(segment
		(start 381.750824 -365.64062)
		(end 382.37541 -365.016034)
		(width 0.508)
		(layer "F.Cu")
		(net "GND")
	)
	(segment
		(start 409.748482 -277.216616)
		(end 410.853382 -277.216616)
		(width 0.381)
		(layer "F.Cu")
		(net "GND")
	)
	(segment
		(start 336.195162 -276.172676)
		(end 335.725008 -275.8948)
		(width 0.254)
		(layer "F.Cu")
		(net "GND")
	)
	(segment
		(start 110.230666 -235.506006)
		(end 110.230666 -234.97032)
		(width 0.254)
		(layer "F.Cu")
		(net "GND")
	)
	(segment
		(start 39.420546 -240.666778)
		(end 38.315646 -240.666778)
		(width 0.381)
		(layer "F.Cu")
		(net "GND")
	)
	(segment
		(start 132.785866 -237.133892)
		(end 132.785612 -236.597952)
		(width 0.2032)
		(layer "F.Cu")
		(net "GND")
	)
	(segment
		(start 173.99381 -365.37265)
		(end 173.98365 -365.38281)
		(width 0.3556)
		(layer "F.Cu")
		(net "GND")
	)
	(segment
		(start 366.159034 -231.436164)
		(end 366.159034 -230.900478)
		(width 0.2032)
		(layer "F.Cu")
		(net "GND")
	)
	(segment
		(start 344.073734 -245.27256)
		(end 344.07348 -245.272306)
		(width 0.2032)
		(layer "F.Cu")
		(net "GND")
	)
	(segment
		(start 337.306666 -42.341546)
		(end 337.581748 -42.811446)
		(width 0.2032)
		(layer "F.Cu")
		(net "GND")
	)
	(segment
		(start 113.519712 -216.78646)
		(end 113.519712 -216.250774)
		(width 0.254)
		(layer "F.Cu")
		(net "GND")
	)
	(segment
		(start 98.123248 -256.361184)
		(end 98.122994 -256.361438)
		(width 0.2032)
		(layer "F.Cu")
		(net "GND")
	)
	(segment
		(start 406.753314 -295.06672)
		(end 405.549862 -295.06672)
		(width 0.381)
		(layer "F.Cu")
		(net "GND")
	)
	(segment
		(start 254.975614 -267.016738)
		(end 256.080514 -267.016738)
		(width 0.381)
		(layer "F.Cu")
		(net "GND")
	)
	(segment
		(start 56.398414 -284.866588)
		(end 57.503314 -284.866588)
		(width 0.381)
		(layer "F.Cu")
		(net "GND")
	)
	(segment
		(start 58.811414 -235.566712)
		(end 57.503314 -235.566712)
		(width 0.381)
		(layer "F.Cu")
		(net "GND")
	)
	(segment
		(start 356.401116 -273.730974)
		(end 356.401116 -274.266914)
		(width 0.2032)
		(layer "F.Cu")
		(net "GND")
	)
	(segment
		(start 262.519414 -242.3668)
		(end 263.624314 -242.3668)
		(width 0.381)
		(layer "F.Cu")
		(net "GND")
	)
	(segment
		(start 337.49488 -227.36683)
		(end 337.49488 -226.831144)
		(width 0.2032)
		(layer "F.Cu")
		(net "GND")
	)
	(segment
		(start 340.314534 -245.27256)
		(end 340.314534 -244.73662)
		(width 0.2032)
		(layer "F.Cu")
		(net "GND")
	)
	(segment
		(start 166.357046 -201.56678)
		(end 165.252146 -201.56678)
		(width 0.381)
		(layer "F.Cu")
		(net "GND")
	)
	(segment
		(start 443.367414 -236.416596)
		(end 444.472314 -236.416596)
		(width 0.381)
		(layer "F.Cu")
		(net "GND")
	)
	(segment
		(start 30.771846 -263.616694)
		(end 31.876746 -263.616694)
		(width 0.381)
		(layer "F.Cu")
		(net "GND")
	)
	(segment
		(start 134.195566 -234.15625)
		(end 134.195566 -234.69219)
		(width 0.2032)
		(layer "F.Cu")
		(net "GND")
	)
	(segment
		(start 346.42298 -228.1809)
		(end 346.423234 -228.180646)
		(width 0.2032)
		(layer "F.Cu")
		(net "GND")
	)
	(segment
		(start 427.733968 -122.62866)
		(end 427.826424 -122.62866)
		(width 0.381)
		(layer "F.Cu")
		(net "GND")
	)
	(segment
		(start 414.297114 -268.71676)
		(end 415.402014 -268.71676)
		(width 0.381)
		(layer "F.Cu")
		(net "GND")
	)
	(segment
		(start 267.724382 -269.566644)
		(end 268.829282 -269.566644)
		(width 0.381)
		(layer "F.Cu")
		(net "GND")
	)
	(segment
		(start 180.339746 -223.666558)
		(end 181.444646 -223.666558)
		(width 0.381)
		(layer "F.Cu")
		(net "GND")
	)
	(segment
		(start 418.397182 -289.966654)
		(end 417.292282 -289.966654)
		(width 0.381)
		(layer "F.Cu")
		(net "GND")
	)
	(segment
		(start 462.555082 -226.216718)
		(end 463.659982 -226.216718)
		(width 0.381)
		(layer "F.Cu")
		(net "GND")
	)
	(segment
		(start 406.753314 -309.51678)
		(end 407.858214 -309.51678)
		(width 0.381)
		(layer "F.Cu")
		(net "GND")
	)
	(segment
		(start 137.484866 -220.855794)
		(end 137.484866 -220.319854)
		(width 0.2032)
		(layer "F.Cu")
		(net "GND")
	)
	(segment
		(start 184.61482 -421.40251)
		(end 184.61482 -420.46652)
		(width 0.3556)
		(layer "F.Cu")
		(net "GND")
	)
	(segment
		(start 463.659982 -226.216718)
		(end 464.764882 -226.216718)
		(width 0.381)
		(layer "F.Cu")
		(net "GND")
	)
	(segment
		(start 126.317248 -268.84757)
		(end 126.316994 -269.38351)
		(width 0.2032)
		(layer "F.Cu")
		(net "GND")
	)
	(segment
		(start 414.297114 -242.3668)
		(end 415.402014 -242.3668)
		(width 0.381)
		(layer "F.Cu")
		(net "GND")
	)
	(segment
		(start 184.439814 -215.166702)
		(end 185.544714 -215.166702)
		(width 0.381)
		(layer "F.Cu")
		(net "GND")
	)
	(segment
		(start 385.534662 -254.197612)
		(end 385.094226 -253.943104)
		(width 0.2032)
		(layer "F.Cu")
		(net "GND")
	)
	(segment
		(start 165.252146 -278.066754)
		(end 166.357046 -278.066754)
		(width 0.381)
		(layer "F.Cu")
		(net "GND")
	)
	(segment
		(start 324.98919 -26.861008)
		(end 324.98919 -26.774648)
		(width 0.3556)
		(layer "F.Cu")
		(net "GND")
	)
	(segment
		(start 109.870494 -272.917158)
		(end 109.870494 -273.453098)
		(width 0.254)
		(layer "F.Cu")
		(net "GND")
	)
	(segment
		(start 370.85778 -236.319822)
		(end 370.858034 -236.319568)
		(width 0.2032)
		(layer "F.Cu")
		(net "GND")
	)
	(segment
		(start 53.403246 -251.716794)
		(end 54.508146 -251.716794)
		(width 0.381)
		(layer "F.Cu")
		(net "GND")
	)
	(segment
		(start 135.135112 -247.714262)
		(end 135.135366 -247.714008)
		(width 0.2032)
		(layer "F.Cu")
		(net "GND")
	)
	(segment
		(start 271.168114 -214.316564)
		(end 270.063214 -214.316564)
		(width 0.381)
		(layer "F.Cu")
		(net "GND")
	)
	(segment
		(start 38.315646 -197.316598)
		(end 37.210746 -197.316598)
		(width 0.381)
		(layer "F.Cu")
		(net "GND")
	)
	(segment
		(start 199.527414 -286.56661)
		(end 200.632314 -286.56661)
		(width 0.381)
		(layer "F.Cu")
		(net "GND")
	)
	(segment
		(start 94.318328 -335.540858)
		(end 94.00413 -335.855056)
		(width 0.1778)
		(layer "F.Cu")
		(net "GND")
	)
	(segment
		(start 110.340648 -267.219938)
		(end 110.340648 -267.755624)
		(width 0.254)
		(layer "F.Cu")
		(net "GND")
	)
	(segment
		(start 6.2357 -97.236788)
		(end 8.38708 -97.236788)
		(width 0.3556)
		(layer "F.Cu")
		(net "GND")
	)
	(segment
		(start 348.30258 -226.553268)
		(end 348.30258 -226.017582)
		(width 0.254)
		(layer "F.Cu")
		(net "GND")
	)
	(segment
		(start 290.355782 -278.916638)
		(end 291.460682 -278.916638)
		(width 0.381)
		(layer "F.Cu")
		(net "GND")
	)
	(segment
		(start 444.472314 -278.066754)
		(end 445.577214 -278.066754)
		(width 0.381)
		(layer "F.Cu")
		(net "GND")
	)
	(segment
		(start 8.140446 -298.466764)
		(end 9.245346 -298.466764)
		(width 0.381)
		(layer "F.Cu")
		(net "GND")
	)
	(segment
		(start 45.859446 -227.066602)
		(end 46.964346 -227.066602)
		(width 0.381)
		(layer "F.Cu")
		(net "GND")
	)
	(segment
		(start 271.168114 -276.366732)
		(end 270.063214 -276.366732)
		(width 0.381)
		(layer "F.Cu")
		(net "GND")
	)
	(segment
		(start 211.972144 -15.517114)
		(end 211.972144 -14.892528)
		(width 0.3556)
		(layer "F.Cu")
		(net "GND")
	)
	(segment
		(start 92.954094 -271.289272)
		(end 92.954348 -271.289526)
		(width 0.2032)
		(layer "F.Cu")
		(net "GND")
	)
	(segment
		(start 207.071214 -232.166668)
		(end 208.176114 -232.166668)
		(width 0.381)
		(layer "F.Cu")
		(net "GND")
	)
	(segment
		(start 176.694084 -31.21025)
		(end 176.694084 -30.33776)
		(width 0.254)
		(layer "F.Cu")
		(net "GND")
	)
	(segment
		(start 57.503314 -316.316614)
		(end 58.608214 -316.316614)
		(width 0.381)
		(layer "F.Cu")
		(net "GND")
	)
	(segment
		(start 196.532246 -289.11677)
		(end 195.427346 -289.11677)
		(width 0.381)
		(layer "F.Cu")
		(net "GND")
	)
	(segment
		(start 383.185162 -279.96388)
		(end 383.184908 -279.964134)
		(width 0.254)
		(layer "F.Cu")
		(net "GND")
	)
	(segment
		(start 285.150814 -217.716608)
		(end 286.255714 -217.716608)
		(width 0.381)
		(layer "F.Cu")
		(net "GND")
	)
	(segment
		(start 270.063214 -225.36658)
		(end 271.168114 -225.36658)
		(width 0.381)
		(layer "F.Cu")
		(net "GND")
	)
	(segment
		(start 439.923682 -241.516662)
		(end 441.028582 -241.516662)
		(width 0.381)
		(layer "F.Cu")
		(net "GND")
	)
	(segment
		(start 129.136394 -264.500106)
		(end 129.136394 -264.50036)
		(width 0.2032)
		(layer "F.Cu")
		(net "GND")
	)
	(segment
		(start 350.65208 -233.877866)
		(end 350.65208 -233.34218)
		(width 0.2032)
		(layer "F.Cu")
		(net "GND")
	)
	(segment
		(start 422.945814 -287.416748)
		(end 421.840914 -287.416748)
		(width 0.381)
		(layer "F.Cu")
		(net "GND")
	)
	(segment
		(start 125.264926 -122.496834)
		(end 125.264926 -123.112784)
		(width 0.3556)
		(layer "F.Cu")
		(net "GND")
	)
	(segment
		(start 110.918752 -334.191102)
		(end 110.625128 -334.191102)
		(width 0.2032)
		(layer "F.Cu")
		(net "GND")
	)
	(segment
		(start 325.087234 -345.853258)
		(end 325.160894 -345.853258)
		(width 0.254)
		(layer "F.Cu")
		(net "GND")
	)
	(segment
		(start 455.011282 -288.266632)
		(end 456.116182 -288.266632)
		(width 0.381)
		(layer "F.Cu")
		(net "GND")
	)
	(segment
		(start 73.54443 -160.212278)
		(end 72.791828 -160.212278)
		(width 0.3556)
		(layer "F.Cu")
		(net "GND")
	)
	(segment
		(start 60.947046 -283.166566)
		(end 62.051946 -283.166566)
		(width 0.381)
		(layer "F.Cu")
		(net "GND")
	)
	(segment
		(start 176.896014 -210.066636)
		(end 178.000914 -210.066636)
		(width 0.381)
		(layer "F.Cu")
		(net "GND")
	)
	(segment
		(start 312.987182 -266.1666)
		(end 314.092082 -266.1666)
		(width 0.381)
		(layer "F.Cu")
		(net "GND")
	)
	(segment
		(start 41.265094 -440.173618)
		(end 42.357294 -440.173618)
		(width 0.3556)
		(layer "F.Cu")
		(net "GND")
	)
	(segment
		(start 166.357046 -265.316716)
		(end 167.461946 -265.316716)
		(width 0.381)
		(layer "F.Cu")
		(net "GND")
	)
	(segment
		(start 102.822248 -284.033468)
		(end 102.821994 -284.033722)
		(width 0.254)
		(layer "F.Cu")
		(net "GND")
	)
	(segment
		(start 342.90254 -57.605168)
		(end 342.402414 -57.45734)
		(width 0.2032)
		(layer "F.Cu")
		(net "GND")
	)
	(segment
		(start 344.363294 -41.401492)
		(end 344.63355 -40.931846)
		(width 0.254)
		(layer "F.Cu")
		(net "GND")
	)
	(segment
		(start 184.439814 -230.466646)
		(end 185.544714 -230.466646)
		(width 0.381)
		(layer "F.Cu")
		(net "GND")
	)
	(segment
		(start 7.035546 -304.416714)
		(end 8.140446 -304.416714)
		(width 0.381)
		(layer "F.Cu")
		(net "GND")
	)
	(segment
		(start 188.988446 -267.016738)
		(end 190.093346 -267.016738)
		(width 0.381)
		(layer "F.Cu")
		(net "GND")
	)
	(segment
		(start 135.135112 -237.411768)
		(end 135.135366 -237.411514)
		(width 0.254)
		(layer "F.Cu")
		(net "GND")
	)
	(segment
		(start 87.205312 -237.411768)
		(end 87.205312 -237.947454)
		(width 0.254)
		(layer "F.Cu")
		(net "GND")
	)
	(segment
		(start 330.896976 -39.295324)
		(end 331.397102 -39.443152)
		(width 0.2032)
		(layer "F.Cu")
		(net "GND")
	)
	(segment
		(start 60.947046 -292.516814)
		(end 62.051946 -292.516814)
		(width 0.381)
		(layer "F.Cu")
		(net "GND")
	)
	(segment
		(start 460.664814 -208.366614)
		(end 459.559914 -208.366614)
		(width 0.381)
		(layer "F.Cu")
		(net "GND")
	)
	(segment
		(start 331.608176 -53.149246)
		(end 331.069188 -53.149246)
		(width 0.2032)
		(layer "F.Cu")
		(net "GND")
	)
	(segment
		(start 48.854614 -211.766658)
		(end 49.959514 -211.766658)
		(width 0.381)
		(layer "F.Cu")
		(net "GND")
	)
	(segment
		(start 382.60528 -245.272306)
		(end 382.60528 -244.73662)
		(width 0.2032)
		(layer "F.Cu")
		(net "GND")
	)
	(segment
		(start 436.928514 -246.616728)
		(end 438.033414 -246.616728)
		(width 0.381)
		(layer "F.Cu")
		(net "GND")
	)
	(segment
		(start 212.724746 -317.166752)
		(end 211.619846 -317.166752)
		(width 0.381)
		(layer "F.Cu")
		(net "GND")
	)
	(segment
		(start 182.549546 -289.11677)
		(end 181.444646 -289.11677)
		(width 0.381)
		(layer "F.Cu")
		(net "GND")
	)
	(segment
		(start 110.151926 -336.27314)
		(end 109.832648 -336.592418)
		(width 0.254)
		(layer "F.Cu")
		(net "GND")
	)
	(segment
		(start 371.672358 -102.106984)
		(end 371.672358 -103.237284)
		(width 0.3556)
		(layer "F.Cu")
		(net "GND")
	)
	(segment
		(start 378.84608 -238.76127)
		(end 378.84608 -238.225584)
		(width 0.2032)
		(layer "F.Cu")
		(net "GND")
	)
	(segment
		(start 208.176114 -211.766658)
		(end 209.281014 -211.766658)
		(width 0.381)
		(layer "F.Cu")
		(net "GND")
	)
	(segment
		(start 190.093346 -244.916706)
		(end 188.988446 -244.916706)
		(width 0.381)
		(layer "F.Cu")
		(net "GND")
	)
	(segment
		(start 137.484866 -233.87812)
		(end 136.545066 -233.34218)
		(width 0.254)
		(layer "F.Cu")
		(net "GND")
	)
	(segment
		(start 190.093346 -240.666778)
		(end 188.988446 -240.666778)
		(width 0.381)
		(layer "F.Cu")
		(net "GND")
	)
	(segment
		(start 271.168114 -261.916672)
		(end 270.063214 -261.916672)
		(width 0.381)
		(layer "F.Cu")
		(net "GND")
	)
	(segment
		(start 43.520614 -282.316682)
		(end 42.415714 -282.316682)
		(width 0.381)
		(layer "F.Cu")
		(net "GND")
	)
	(segment
		(start 29.666946 -229.616762)
		(end 30.771846 -229.616762)
		(width 0.381)
		(layer "F.Cu")
		(net "GND")
	)
	(segment
		(start 107.880912 -216.250774)
		(end 107.881166 -216.25052)
		(width 0.254)
		(layer "F.Cu")
		(net "GND")
	)
	(segment
		(start 294.904414 -210.916774)
		(end 293.799514 -210.916774)
		(width 0.381)
		(layer "F.Cu")
		(net "GND")
	)
	(segment
		(start 134.305294 -285.939484)
		(end 134.305294 -286.475424)
		(width 0.2032)
		(layer "F.Cu")
		(net "GND")
	)
	(segment
		(start 449.677282 -228.766624)
		(end 448.572382 -228.766624)
		(width 0.381)
		(layer "F.Cu")
		(net "GND")
	)
	(segment
		(start 87.675466 -219.228162)
		(end 87.675466 -218.692222)
		(width 0.2032)
		(layer "F.Cu")
		(net "GND")
	)
	(segment
		(start 23.228046 -290.816792)
		(end 24.332946 -290.816792)
		(width 0.381)
		(layer "F.Cu")
		(net "GND")
	)
	(segment
		(start 201.42073 -102.235)
		(end 202.0824 -102.235)
		(width 0.3556)
		(layer "F.Cu")
		(net "GND")
	)
	(segment
		(start 212.724746 -311.216802)
		(end 211.619846 -311.216802)
		(width 0.381)
		(layer "F.Cu")
		(net "GND")
	)
	(segment
		(start 349.712534 -238.761524)
		(end 349.71228 -238.76127)
		(width 0.2032)
		(layer "F.Cu")
		(net "GND")
	)
	(segment
		(start 423.19194 -382.184148)
		(end 423.36974 -382.361948)
		(width 0.3556)
		(layer "F.Cu")
		(net "GND")
	)
	(segment
		(start 448.48018 -115.312444)
		(end 448.48018 -116.335048)
		(width 0.3556)
		(layer "F.Cu")
		(net "GND")
	)
	(segment
		(start 366.738916 -273.730974)
		(end 366.738662 -274.266914)
		(width 0.254)
		(layer "F.Cu")
		(net "GND")
	)
	(segment
		(start 428.279814 -283.166566)
		(end 429.384714 -283.166566)
		(width 0.381)
		(layer "F.Cu")
		(net "GND")
	)
	(segment
		(start 359.11028 -238.76127)
		(end 359.11028 -238.225584)
		(width 0.254)
		(layer "F.Cu")
		(net "GND")
	)
	(segment
		(start 383.340102 -343.391998)
		(end 383.046478 -343.391998)
		(width 0.2032)
		(layer "F.Cu")
		(net "GND")
	)
	(segment
		(start 425.607734 -367.0681)
		(end 425.44492 -367.0681)
		(width 0.381)
		(layer "F.Cu")
		(net "GND")
	)
	(segment
		(start 87.315294 -282.683966)
		(end 87.315294 -283.219906)
		(width 0.2032)
		(layer "F.Cu")
		(net "GND")
	)
	(segment
		(start 18.679414 -314.616592)
		(end 19.784314 -314.616592)
		(width 0.381)
		(layer "F.Cu")
		(net "GND")
	)
	(segment
		(start 432.379882 -258.516628)
		(end 433.484782 -258.516628)
		(width 0.381)
		(layer "F.Cu")
		(net "GND")
	)
	(segment
		(start 129.606294 -276.172676)
		(end 129.606548 -276.708616)
		(width 0.2032)
		(layer "F.Cu")
		(net "GND")
	)
	(segment
		(start 99.422712 -231.436418)
		(end 99.422966 -231.436164)
		(width 0.2032)
		(layer "F.Cu")
		(net "GND")
	)
	(segment
		(start 170.457114 -312.91657)
		(end 171.821348 -312.91657)
		(width 0.381)
		(layer "F.Cu")
		(net "GND")
	)
	(segment
		(start 292.694614 -317.166752)
		(end 293.799514 -317.166752)
		(width 0.381)
		(layer "F.Cu")
		(net "GND")
	)
	(segment
		(start 420.736014 -195.616576)
		(end 421.840914 -195.616576)
		(width 0.381)
		(layer "F.Cu")
		(net "GND")
	)
	(segment
		(start 458.24775 -383.684272)
		(end 458.24775 -382.90627)
		(width 0.1778)
		(layer "F.Cu")
		(net "GND")
	)
	(segment
		(start 127.616712 -242.830858)
		(end 127.616712 -242.295172)
		(width 0.2032)
		(layer "F.Cu")
		(net "GND")
	)
	(segment
		(start 176.896014 -312.91657)
		(end 178.000914 -312.91657)
		(width 0.381)
		(layer "F.Cu")
		(net "GND")
	)
	(segment
		(start 101.412294 -276.708362)
		(end 101.412548 -276.708616)
		(width 0.254)
		(layer "F.Cu")
		(net "GND")
	)
	(segment
		(start 360.050334 -224.111566)
		(end 360.050334 -223.575626)
		(width 0.2032)
		(layer "F.Cu")
		(net "GND")
	)
	(segment
		(start 337.900264 -57.605168)
		(end 337.900264 -58.43524)
		(width 0.254)
		(layer "F.Cu")
		(net "GND")
	)
	(segment
		(start 90.964512 -216.250774)
		(end 90.964766 -216.25052)
		(width 0.254)
		(layer "F.Cu")
		(net "GND")
	)
	(segment
		(start 428.279814 -267.016738)
		(end 429.384714 -267.016738)
		(width 0.381)
		(layer "F.Cu")
		(net "GND")
	)
	(segment
		(start 30.771846 -210.916774)
		(end 31.876746 -210.916774)
		(width 0.381)
		(layer "F.Cu")
		(net "GND")
	)
	(segment
		(start 102.822248 -273.730974)
		(end 102.822248 -274.26666)
		(width 0.2032)
		(layer "F.Cu")
		(net "GND")
	)
	(segment
		(start 125.737112 -226.553268)
		(end 125.737112 -226.017582)
		(width 0.254)
		(layer "F.Cu")
		(net "GND")
	)
	(segment
		(start 419.705282 -294.216582)
		(end 418.397182 -294.216582)
		(width 0.381)
		(layer "F.Cu")
		(net "GND")
	)
	(segment
		(start 157.489144 -313.766708)
		(end 158.813246 -313.766708)
		(width 0.381)
		(layer "F.Cu")
		(net "GND")
	)
	(segment
		(start 92.954094 -279.96388)
		(end 92.954348 -279.964134)
		(width 0.254)
		(layer "F.Cu")
		(net "GND")
	)
	(segment
		(start 294.904414 -263.616694)
		(end 293.799514 -263.616694)
		(width 0.381)
		(layer "F.Cu")
		(net "GND")
	)
	(segment
		(start 33.767014 -204.116686)
		(end 34.871914 -204.116686)
		(width 0.381)
		(layer "F.Cu")
		(net "GND")
	)
	(segment
		(start 464.764882 -291.666676)
		(end 463.659982 -291.666676)
		(width 0.381)
		(layer "F.Cu")
		(net "GND")
	)
	(segment
		(start 427.045882 -230.466646)
		(end 425.940982 -230.466646)
		(width 0.381)
		(layer "F.Cu")
		(net "GND")
	)
	(segment
		(start 34.871914 -228.766624)
		(end 35.976814 -228.766624)
		(width 0.381)
		(layer "F.Cu")
		(net "GND")
	)
	(segment
		(start 118.49608 -120.246648)
		(end 118.49608 -120.856248)
		(width 0.3556)
		(layer "F.Cu")
		(net "GND")
	)
	(segment
		(start 58.0517 -106.784648)
		(end 58.0517 -107.500674)
		(width 0.3556)
		(layer "F.Cu")
		(net "GND")
	)
	(segment
		(start 365.328962 -266.405868)
		(end 365.329216 -266.941808)
		(width 0.2032)
		(layer "F.Cu")
		(net "GND")
	)
	(segment
		(start 424.836082 -219.41663)
		(end 425.940982 -219.41663)
		(width 0.381)
		(layer "F.Cu")
		(net "GND")
	)
	(segment
		(start 7.035546 -214.316564)
		(end 8.140446 -214.316564)
		(width 0.381)
		(layer "F.Cu")
		(net "GND")
	)
	(segment
		(start 19.784314 -271.266666)
		(end 20.889214 -271.266666)
		(width 0.381)
		(layer "F.Cu")
		(net "GND")
	)
	(segment
		(start 436.928514 -204.96657)
		(end 438.033414 -204.96657)
		(width 0.381)
		(layer "F.Cu")
		(net "GND")
	)
	(segment
		(start 12.240514 -194.766692)
		(end 13.345414 -194.766692)
		(width 0.381)
		(layer "F.Cu")
		(net "GND")
	)
	(segment
		(start 297.899582 -245.76659)
		(end 299.004482 -245.76659)
		(width 0.381)
		(layer "F.Cu")
		(net "GND")
	)
	(segment
		(start 458.81671 -39.765478)
		(end 458.81671 -39.124128)
		(width 0.3556)
		(layer "F.Cu")
		(net "GND")
	)
	(segment
		(start 345.270836 -53.669184)
		(end 345.554554 -53.952902)
		(width 0.254)
		(layer "F.Cu")
		(net "GND")
	)
	(segment
		(start 334.099408 -49.650396)
		(end 334.499458 -50.050446)
		(width 0.2032)
		(layer "F.Cu")
		(net "GND")
	)
	(segment
		(start 178.952398 -402.255482)
		(end 178.336448 -402.255482)
		(width 0.254)
		(layer "F.Cu")
		(net "GND")
	)
	(segment
		(start 290.355782 -211.766658)
		(end 291.460682 -211.766658)
		(width 0.381)
		(layer "F.Cu")
		(net "GND")
	)
	(segment
		(start 177.355754 -111.375444)
		(end 176.955704 -110.975394)
		(width 0.3556)
		(layer "F.Cu")
		(net "GND")
	)
	(segment
		(start 372.377716 -286.7533)
		(end 372.377716 -287.288986)
		(width 0.254)
		(layer "F.Cu")
		(net "GND")
	)
	(segment
		(start 372.267734 -238.761524)
		(end 372.26748 -238.76127)
		(width 0.2032)
		(layer "F.Cu")
		(net "GND")
	)
	(segment
		(start 334.205834 -228.1809)
		(end 334.205834 -227.64496)
		(width 0.2032)
		(layer "F.Cu")
		(net "GND")
	)
	(segment
		(start 100.57384 -80.935322)
		(end 101.27488 -80.935322)
		(width 0.3556)
		(layer "F.Cu")
		(net "GND")
	)
	(segment
		(start 99.422712 -247.714262)
		(end 99.422712 -247.178576)
		(width 0.2032)
		(layer "F.Cu")
		(net "GND")
	)
	(segment
		(start 59.819794 -313.766708)
		(end 60.947046 -313.766708)
		(width 0.381)
		(layer "F.Cu")
		(net "GND")
	)
	(segment
		(start 345.554554 -40.946578)
		(end 345.15171 -41.349422)
		(width 0.2032)
		(layer "F.Cu")
		(net "GND")
	)
	(segment
		(start 453.121014 -268.71676)
		(end 452.016114 -268.71676)
		(width 0.381)
		(layer "F.Cu")
		(net "GND")
	)
	(segment
		(start 307.782214 -267.016738)
		(end 308.887114 -267.016738)
		(width 0.381)
		(layer "F.Cu")
		(net "GND")
	)
	(segment
		(start 352.641916 -277.521924)
		(end 352.641662 -277.522178)
		(width 0.2032)
		(layer "F.Cu")
		(net "GND")
	)
	(segment
		(start 7.035546 -210.916774)
		(end 8.140446 -210.916774)
		(width 0.381)
		(layer "F.Cu")
		(net "GND")
	)
	(segment
		(start 65.047114 -267.866622)
		(end 66.152014 -267.866622)
		(width 0.381)
		(layer "F.Cu")
		(net "GND")
	)
	(segment
		(start 452.016114 -250.016772)
		(end 450.911214 -250.016772)
		(width 0.381)
		(layer "F.Cu")
		(net "GND")
	)
	(segment
		(start 186.649614 -286.56661)
		(end 185.544714 -286.56661)
		(width 0.381)
		(layer "F.Cu")
		(net "GND")
	)
	(segment
		(start 368.038634 -220.041724)
		(end 368.038634 -219.506038)
		(width 0.254)
		(layer "F.Cu")
		(net "GND")
	)
	(segment
		(start 414.297114 -306.116736)
		(end 415.402014 -306.116736)
		(width 0.381)
		(layer "F.Cu")
		(net "GND")
	)
	(segment
		(start 435.823614 -301.866808)
		(end 436.928514 -301.866808)
		(width 0.381)
		(layer "F.Cu")
		(net "GND")
	)
	(segment
		(start 376.49658 -242.830858)
		(end 376.49658 -242.295172)
		(width 0.2032)
		(layer "F.Cu")
		(net "GND")
	)
	(segment
		(start 102.821994 -265.592306)
		(end 102.822248 -265.592306)
		(width 0.381)
		(layer "F.Cu")
		(net "GND")
	)
	(segment
		(start 29.666946 -236.416596)
		(end 30.771846 -236.416596)
		(width 0.381)
		(layer "F.Cu")
		(net "GND")
	)
	(segment
		(start 131.375912 -219.506292)
		(end 131.376166 -219.506038)
		(width 0.254)
		(layer "F.Cu")
		(net "GND")
	)
	(segment
		(start 312.987182 -305.266598)
		(end 314.092082 -305.266598)
		(width 0.381)
		(layer "F.Cu")
		(net "GND")
	)
	(segment
		(start 263.624314 -221.96679)
		(end 264.729214 -221.96679)
		(width 0.381)
		(layer "F.Cu")
		(net "GND")
	)
	(segment
		(start 126.207012 -232.250234)
		(end 126.207012 -231.714548)
		(width 0.2032)
		(layer "F.Cu")
		(net "GND")
	)
	(segment
		(start 382.715516 -283.497782)
		(end 382.715516 -284.033468)
		(width 0.254)
		(layer "F.Cu")
		(net "GND")
	)
	(segment
		(start 338.120736 -43.751246)
		(end 337.581748 -43.751246)
		(width 0.2032)
		(layer "F.Cu")
		(net "GND")
	)
	(segment
		(start 377.43638 -231.436418)
		(end 377.436634 -231.436164)
		(width 0.2032)
		(layer "F.Cu")
		(net "GND")
	)
	(segment
		(start 375.666762 -257.175254)
		(end 375.666762 -256.639314)
		(width 0.2032)
		(layer "F.Cu")
		(net "GND")
	)
	(segment
		(start 124.327412 -250.15571)
		(end 124.327412 -249.620024)
		(width 0.2032)
		(layer "F.Cu")
		(net "GND")
	)
	(segment
		(start 23.228046 -216.016586)
		(end 24.332946 -216.016586)
		(width 0.381)
		(layer "F.Cu")
		(net "GND")
	)
	(segment
		(start 406.753314 -244.916706)
		(end 407.858214 -244.916706)
		(width 0.381)
		(layer "F.Cu")
		(net "GND")
	)
	(segment
		(start 335.615534 -215.972644)
		(end 335.615534 -215.436958)
		(width 0.2032)
		(layer "F.Cu")
		(net "GND")
	)
	(segment
		(start 339.374734 -220.855794)
		(end 339.374734 -220.319854)
		(width 0.2032)
		(layer "F.Cu")
		(net "GND")
	)
	(segment
		(start 106.941112 -222.76181)
		(end 106.941366 -222.761556)
		(width 0.254)
		(layer "F.Cu")
		(net "GND")
	)
	(segment
		(start 425.940982 -219.41663)
		(end 427.045882 -219.41663)
		(width 0.381)
		(layer "F.Cu")
		(net "GND")
	)
	(segment
		(start 182.549546 -301.866808)
		(end 181.444646 -301.866808)
		(width 0.381)
		(layer "F.Cu")
		(net "GND")
	)
	(segment
		(start 341.37727 -48.450246)
		(end 341.105998 -47.980346)
		(width 0.2032)
		(layer "F.Cu")
		(net "GND")
	)
	(segment
		(start 11.135614 -301.01667)
		(end 12.240514 -301.01667)
		(width 0.381)
		(layer "F.Cu")
		(net "GND")
	)
	(segment
		(start 125.737112 -234.69219)
		(end 125.737366 -234.691936)
		(width 0.2032)
		(layer "F.Cu")
		(net "GND")
	)
	(segment
		(start 95.123508 -92.134944)
		(end 94.9452 -92.313252)
		(width 0.3556)
		(layer "F.Cu")
		(net "GND")
	)
	(segment
		(start 360.520234 -220.041724)
		(end 360.520234 -219.506038)
		(width 0.254)
		(layer "F.Cu")
		(net "GND")
	)
	(segment
		(start 439.923682 -310.366664)
		(end 441.028582 -310.366664)
		(width 0.381)
		(layer "F.Cu")
		(net "GND")
	)
	(segment
		(start 167.461946 -306.116736)
		(end 166.357046 -306.116736)
		(width 0.381)
		(layer "F.Cu")
		(net "GND")
	)
	(segment
		(start 181.444646 -292.516814)
		(end 180.339746 -292.516814)
		(width 0.381)
		(layer "F.Cu")
		(net "GND")
	)
	(segment
		(start 132.315712 -246.08663)
		(end 132.315712 -245.55069)
		(width 0.2032)
		(layer "F.Cu")
		(net "GND")
	)
	(segment
		(start 179.105814 -228.766624)
		(end 178.000914 -228.766624)
		(width 0.381)
		(layer "F.Cu")
		(net "GND")
	)
	(segment
		(start 272.273014 -214.316564)
		(end 271.168114 -214.316564)
		(width 0.381)
		(layer "F.Cu")
		(net "GND")
	)
	(segment
		(start 310.207914 -285.716726)
		(end 308.887114 -285.716726)
		(width 0.381)
		(layer "F.Cu")
		(net "GND")
	)
	(segment
		(start 356.401116 -271.011142)
		(end 356.400862 -271.011396)
		(width 0.2032)
		(layer "F.Cu")
		(net "GND")
	)
	(segment
		(start 367.09858 -223.297496)
		(end 367.09858 -222.76181)
		(width 0.254)
		(layer "F.Cu")
		(net "GND")
	)
	(segment
		(start 383.545334 -248.528078)
		(end 383.545334 -247.992138)
		(width 0.254)
		(layer "F.Cu")
		(net "GND")
	)
	(segment
		(start 89.554812 -237.133638)
		(end 89.554812 -236.597952)
		(width 0.254)
		(layer "F.Cu")
		(net "GND")
	)
	(segment
		(start 279.816814 -306.116736)
		(end 278.711914 -306.116736)
		(width 0.381)
		(layer "F.Cu")
		(net "GND")
	)
	(segment
		(start 137.594594 -278.614378)
		(end 138.064494 -278.336502)
		(width 0.254)
		(layer "F.Cu")
		(net "GND")
	)
	(segment
		(start 128.556766 -220.041724)
		(end 128.556766 -219.506038)
		(width 0.254)
		(layer "F.Cu")
		(net "GND")
	)
	(segment
		(start 450.307202 -78.229968)
		(end 450.307202 -78.861412)
		(width 0.381)
		(layer "F.Cu")
		(net "GND")
	)
	(segment
		(start 149.352 -35.794188)
		(end 149.01672 -35.794188)
		(width 0.3556)
		(layer "F.Cu")
		(net "GND")
	)
	(segment
		(start 60.947046 -248.31675)
		(end 62.051946 -248.31675)
		(width 0.381)
		(layer "F.Cu")
		(net "GND")
	)
	(segment
		(start 27.328114 -215.166702)
		(end 28.433014 -215.166702)
		(width 0.381)
		(layer "F.Cu")
		(net "GND")
	)
	(segment
		(start 448.572382 -235.566712)
		(end 449.677282 -235.566712)
		(width 0.381)
		(layer "F.Cu")
		(net "GND")
	)
	(segment
		(start 375.666762 -266.405868)
		(end 375.667016 -266.941808)
		(width 0.2032)
		(layer "F.Cu")
		(net "GND")
	)
	(segment
		(start 381.750824 -365.64062)
		(end 382.37541 -366.265206)
		(width 0.508)
		(layer "F.Cu")
		(net "GND")
	)
	(segment
		(start 282.811982 -297.616626)
		(end 283.916882 -297.616626)
		(width 0.381)
		(layer "F.Cu")
		(net "GND")
	)
	(segment
		(start 280.14422 -424.821096)
		(end 280.14422 -423.84726)
		(width 0.3556)
		(layer "F.Cu")
		(net "GND")
	)
	(segment
		(start 176.896014 -239.81664)
		(end 178.000914 -239.81664)
		(width 0.381)
		(layer "F.Cu")
		(net "GND")
	)
	(segment
		(start 263.624314 -216.016586)
		(end 264.729214 -216.016586)
		(width 0.381)
		(layer "F.Cu")
		(net "GND")
	)
	(segment
		(start 420.156894 -8.320024)
		(end 420.156894 -7.215124)
		(width 0.3556)
		(layer "F.Cu")
		(net "GND")
	)
	(segment
		(start 278.839676 -16.576548)
		(end 278.839676 -17.241774)
		(width 0.3556)
		(layer "F.Cu")
		(net "GND")
	)
	(segment
		(start 458.455014 -306.116736)
		(end 459.559914 -306.116736)
		(width 0.381)
		(layer "F.Cu")
		(net "GND")
	)
	(segment
		(start 347.36278 -229.808786)
		(end 347.363034 -229.808532)
		(width 0.2032)
		(layer "F.Cu")
		(net "GND")
	)
	(segment
		(start 185.544714 -294.216582)
		(end 184.439814 -294.216582)
		(width 0.381)
		(layer "F.Cu")
		(net "GND")
	)
	(segment
		(start 370.498116 -286.7533)
		(end 370.498116 -287.288986)
		(width 0.254)
		(layer "F.Cu")
		(net "GND")
	)
	(segment
		(start 10.01014 -97.683828)
		(end 9.90981 -97.784158)
		(width 0.3556)
		(layer "F.Cu")
		(net "GND")
	)
	(segment
		(start 271.168114 -283.166566)
		(end 272.273014 -283.166566)
		(width 0.381)
		(layer "F.Cu")
		(net "GND")
	)
	(segment
		(start 448.572382 -284.866588)
		(end 447.467482 -284.866588)
		(width 0.381)
		(layer "F.Cu")
		(net "GND")
	)
	(segment
		(start 178.000914 -316.316614)
		(end 179.105814 -316.316614)
		(width 0.381)
		(layer "F.Cu")
		(net "GND")
	)
	(segment
		(start 375.666762 -258.802886)
		(end 375.667016 -258.80314)
		(width 0.2032)
		(layer "F.Cu")
		(net "GND")
	)
	(segment
		(start 344.07348 -250.15571)
		(end 344.07348 -249.620024)
		(width 0.2032)
		(layer "F.Cu")
		(net "GND")
	)
	(segment
		(start 435.823614 -279.766776)
		(end 436.928514 -279.766776)
		(width 0.381)
		(layer "F.Cu")
		(net "GND")
	)
	(segment
		(start 113.629694 -269.66164)
		(end 113.629694 -270.19758)
		(width 0.254)
		(layer "F.Cu")
		(net "GND")
	)
	(segment
		(start 105.641648 -278.614378)
		(end 105.641648 -279.150318)
		(width 0.254)
		(layer "F.Cu")
		(net "GND")
	)
	(segment
		(start 367.208562 -289.195002)
		(end 367.208562 -289.807142)
		(width 0.254)
		(layer "F.Cu")
		(net "GND")
	)
	(segment
		(start 97.653094 -266.405868)
		(end 97.653094 -266.941808)
		(width 0.2032)
		(layer "F.Cu")
		(net "GND")
	)
	(segment
		(start 458.455014 -285.716726)
		(end 459.559914 -285.716726)
		(width 0.381)
		(layer "F.Cu")
		(net "GND")
	)
	(segment
		(start 272.273014 -272.116804)
		(end 271.168114 -272.116804)
		(width 0.381)
		(layer "F.Cu")
		(net "GND")
	)
	(segment
		(start 386.443728 -28.70962)
		(end 386.82168 -28.70962)
		(width 0.3556)
		(layer "F.Cu")
		(net "GND")
	)
	(segment
		(start 27.328114 -239.81664)
		(end 28.433014 -239.81664)
		(width 0.381)
		(layer "F.Cu")
		(net "GND")
	)
	(segment
		(start 444.472314 -204.96657)
		(end 443.367414 -204.96657)
		(width 0.381)
		(layer "F.Cu")
		(net "GND")
	)
	(segment
		(start 421.840914 -287.416748)
		(end 420.736014 -287.416748)
		(width 0.381)
		(layer "F.Cu")
		(net "GND")
	)
	(segment
		(start 164.018214 -301.01667)
		(end 162.913314 -301.01667)
		(width 0.381)
		(layer "F.Cu")
		(net "GND")
	)
	(segment
		(start 308.887114 -244.916706)
		(end 309.992014 -244.916706)
		(width 0.381)
		(layer "F.Cu")
		(net "GND")
	)
	(segment
		(start 340.424516 -286.7533)
		(end 340.424516 -287.28924)
		(width 0.254)
		(layer "F.Cu")
		(net "GND")
	)
	(segment
		(start 39.420546 -225.36658)
		(end 38.315646 -225.36658)
		(width 0.381)
		(layer "F.Cu")
		(net "GND")
	)
	(segment
		(start 274.163282 -221.116652)
		(end 275.268182 -221.116652)
		(width 0.381)
		(layer "F.Cu")
		(net "GND")
	)
	(segment
		(start 354.411534 -230.622602)
		(end 354.411534 -230.086662)
		(width 0.2032)
		(layer "F.Cu")
		(net "GND")
	)
	(segment
		(start 86.265766 -245.545864)
		(end 86.265766 -245.55069)
		(width 0.2032)
		(layer "F.Cu")
		(net "GND")
	)
	(segment
		(start 260.180582 -262.76681)
		(end 259.075682 -262.76681)
		(width 0.381)
		(layer "F.Cu")
		(net "GND")
	)
	(segment
		(start 337.604862 -259.081016)
		(end 337.604862 -259.616956)
		(width 0.2032)
		(layer "F.Cu")
		(net "GND")
	)
	(segment
		(start 48.854614 -282.316682)
		(end 49.959514 -282.316682)
		(width 0.381)
		(layer "F.Cu")
		(net "GND")
	)
	(segment
		(start 208.176114 -289.966654)
		(end 209.281014 -289.966654)
		(width 0.381)
		(layer "F.Cu")
		(net "GND")
	)
	(segment
		(start 383.655062 -270.475456)
		(end 383.655062 -271.011396)
		(width 0.254)
		(layer "F.Cu")
		(net "GND")
	)
	(segment
		(start 107.521248 -280.77795)
		(end 107.520994 -280.778204)
		(width 0.254)
		(layer "F.Cu")
		(net "GND")
	)
	(segment
		(start 157.609794 -295.06672)
		(end 158.813246 -295.06672)
		(width 0.381)
		(layer "F.Cu")
		(net "GND")
	)
	(segment
		(start 31.307278 -139.066524)
		(end 31.307278 -138.41984)
		(width 0.3556)
		(layer "F.Cu")
		(net "GND")
	)
	(segment
		(start 293.799514 -295.06672)
		(end 292.694614 -295.06672)
		(width 0.381)
		(layer "F.Cu")
		(net "GND")
	)
	(segment
		(start 123.027694 -279.428194)
		(end 123.027694 -279.96388)
		(width 0.254)
		(layer "F.Cu")
		(net "GND")
	)
	(segment
		(start 131.956048 -267.219938)
		(end 131.956048 -267.755878)
		(width 0.2032)
		(layer "F.Cu")
		(net "GND")
	)
	(segment
		(start 98.953066 -220.855794)
		(end 98.953066 -220.319854)
		(width 0.2032)
		(layer "F.Cu")
		(net "GND")
	)
	(segment
		(start 364.88878 -390.749028)
		(end 364.499652 -391.138156)
		(width 0.3556)
		(layer "F.Cu")
		(net "GND")
	)
	(segment
		(start 99.422966 -244.45849)
		(end 99.422966 -243.922804)
		(width 0.2032)
		(layer "F.Cu")
		(net "GND")
	)
	(segment
		(start 38.315646 -298.466764)
		(end 37.210746 -298.466764)
		(width 0.381)
		(layer "F.Cu")
		(net "GND")
	)
	(segment
		(start 444.472314 -216.016586)
		(end 443.367414 -216.016586)
		(width 0.381)
		(layer "F.Cu")
		(net "GND")
	)
	(segment
		(start 127.288544 -74.453242)
		(end 126.653544 -74.453242)
		(width 0.3556)
		(layer "F.Cu")
		(net "GND")
	)
	(segment
		(start 135.245094 -264.778236)
		(end 135.245348 -265.314176)
		(width 0.2032)
		(layer "F.Cu")
		(net "GND")
	)
	(segment
		(start 202.971146 -203.266802)
		(end 204.076046 -203.266802)
		(width 0.381)
		(layer "F.Cu")
		(net "GND")
	)
	(segment
		(start 301.343314 -265.316716)
		(end 302.448214 -265.316716)
		(width 0.381)
		(layer "F.Cu")
		(net "GND")
	)
	(segment
		(start 190.80988 -134.095998)
		(end 190.80988 -134.711948)
		(width 0.3556)
		(layer "F.Cu")
		(net "GND")
	)
	(segment
		(start 463.659982 -305.266598)
		(end 462.555082 -305.266598)
		(width 0.381)
		(layer "F.Cu")
		(net "GND")
	)
	(segment
		(start 278.711914 -295.06672)
		(end 277.607014 -295.06672)
		(width 0.381)
		(layer "F.Cu")
		(net "GND")
	)
	(segment
		(start 379.786134 -245.27256)
		(end 379.786134 -244.73662)
		(width 0.2032)
		(layer "F.Cu")
		(net "GND")
	)
	(segment
		(start 463.659982 -247.466612)
		(end 464.764882 -247.466612)
		(width 0.381)
		(layer "F.Cu")
		(net "GND")
	)
	(segment
		(start 337.495134 -235.506006)
		(end 337.49488 -235.505752)
		(width 0.2032)
		(layer "F.Cu")
		(net "GND")
	)
	(segment
		(start 406.753314 -276.366732)
		(end 407.858214 -276.366732)
		(width 0.381)
		(layer "F.Cu")
		(net "GND")
	)
	(segment
		(start 103.291894 -278.336248)
		(end 103.292148 -278.336502)
		(width 0.254)
		(layer "F.Cu")
		(net "GND")
	)
	(segment
		(start 190.093346 -251.716794)
		(end 188.988446 -251.716794)
		(width 0.381)
		(layer "F.Cu")
		(net "GND")
	)
	(segment
		(start 449.677282 -215.166702)
		(end 448.572382 -215.166702)
		(width 0.381)
		(layer "F.Cu")
		(net "GND")
	)
	(segment
		(start 275.268182 -301.01667)
		(end 274.163282 -301.01667)
		(width 0.381)
		(layer "F.Cu")
		(net "GND")
	)
	(segment
		(start 355.930962 -279.428194)
		(end 355.930962 -279.964134)
		(width 0.254)
		(layer "F.Cu")
		(net "GND")
	)
	(segment
		(start 33.767014 -238.116618)
		(end 34.871914 -238.116618)
		(width 0.381)
		(layer "F.Cu")
		(net "GND")
	)
	(segment
		(start 33.767014 -232.166668)
		(end 34.871914 -232.166668)
		(width 0.381)
		(layer "F.Cu")
		(net "GND")
	)
	(segment
		(start 8.140446 -195.616576)
		(end 9.245346 -195.616576)
		(width 0.381)
		(layer "F.Cu")
		(net "GND")
	)
	(segment
		(start 309.57774 -430.33696)
		(end 309.57774 -429.699928)
		(width 0.3556)
		(layer "F.Cu")
		(net "GND")
	)
	(segment
		(start 452.016114 -272.116804)
		(end 450.911214 -272.116804)
		(width 0.381)
		(layer "F.Cu")
		(net "GND")
	)
	(segment
		(start 382.715516 -284.033468)
		(end 382.715262 -284.033722)
		(width 0.254)
		(layer "F.Cu")
		(net "GND")
	)
	(segment
		(start 30.771846 -272.116804)
		(end 31.876746 -272.116804)
		(width 0.381)
		(layer "F.Cu")
		(net "GND")
	)
	(segment
		(start 380.365762 -257.175254)
		(end 380.365762 -256.639314)
		(width 0.2032)
		(layer "F.Cu")
		(net "GND")
	)
	(segment
		(start 171.562014 -228.766624)
		(end 170.457114 -228.766624)
		(width 0.381)
		(layer "F.Cu")
		(net "GND")
	)
	(segment
		(start 7.035546 -221.96679)
		(end 8.140446 -221.96679)
		(width 0.381)
		(layer "F.Cu")
		(net "GND")
	)
	(segment
		(start 177.108104 -49.800002)
		(end 178.289204 -49.800002)
		(width 0.254)
		(layer "F.Cu")
		(net "GND")
	)
	(segment
		(start 135.605266 -222.48368)
		(end 135.605266 -221.94774)
		(width 0.254)
		(layer "F.Cu")
		(net "GND")
	)
	(segment
		(start 459.559914 -217.716608)
		(end 458.455014 -217.716608)
		(width 0.381)
		(layer "F.Cu")
		(net "GND")
	)
	(segment
		(start 91.904566 -220.041724)
		(end 91.904566 -219.506038)
		(width 0.254)
		(layer "F.Cu")
		(net "GND")
	)
	(segment
		(start 211.619846 -295.06672)
		(end 210.514946 -295.06672)
		(width 0.381)
		(layer "F.Cu")
		(net "GND")
	)
	(segment
		(start 427.045882 -305.266598)
		(end 425.940982 -305.266598)
		(width 0.381)
		(layer "F.Cu")
		(net "GND")
	)
	(segment
		(start 94.364048 -287.288986)
		(end 94.363794 -287.28924)
		(width 0.254)
		(layer "F.Cu")
		(net "GND")
	)
	(segment
		(start 297.899582 -250.866656)
		(end 299.004482 -250.866656)
		(width 0.381)
		(layer "F.Cu")
		(net "GND")
	)
	(segment
		(start 237.92942 -246.530368)
		(end 239.61852 -246.530368)
		(width 0.3556)
		(layer "F.Cu")
		(net "GND")
	)
	(segment
		(start 332.422246 -44.221146)
		(end 331.881988 -44.221146)
		(width 0.2032)
		(layer "F.Cu")
		(net "GND")
	)
	(segment
		(start 381.19558 -219.506292)
		(end 381.195834 -219.506038)
		(width 0.254)
		(layer "F.Cu")
		(net "GND")
	)
	(segment
		(start 406.753314 -248.31675)
		(end 407.858214 -248.31675)
		(width 0.381)
		(layer "F.Cu")
		(net "GND")
	)
	(segment
		(start 187.883546 -296.766742)
		(end 188.988446 -296.766742)
		(width 0.381)
		(layer "F.Cu")
		(net "GND")
	)
	(segment
		(start 443.367414 -289.11677)
		(end 444.472314 -289.11677)
		(width 0.381)
		(layer "F.Cu")
		(net "GND")
	)
	(segment
		(start 290.355782 -282.316682)
		(end 291.460682 -282.316682)
		(width 0.381)
		(layer "F.Cu")
		(net "GND")
	)
	(segment
		(start 42.415714 -288.266632)
		(end 41.310814 -288.266632)
		(width 0.381)
		(layer "F.Cu")
		(net "GND")
	)
	(segment
		(start 135.245094 -269.66164)
		(end 135.245348 -270.167862)
		(width 0.2032)
		(layer "F.Cu")
		(net "GND")
	)
	(segment
		(start 112.75314 -395.122908)
		(end 112.512094 -394.881862)
		(width 0.3556)
		(layer "F.Cu")
		(net "GND")
	)
	(segment
		(start 405.648414 -248.31675)
		(end 406.753314 -248.31675)
		(width 0.381)
		(layer "F.Cu")
		(net "GND")
	)
	(segment
		(start 453.121014 -283.166566)
		(end 452.016114 -283.166566)
		(width 0.381)
		(layer "F.Cu")
		(net "GND")
	)
	(segment
		(start 158.813246 -298.466764)
		(end 159.918146 -298.466764)
		(width 0.381)
		(layer "F.Cu")
		(net "GND")
	)
	(segment
		(start 364.859316 -280.242264)
		(end 364.859316 -280.778204)
		(width 0.254)
		(layer "F.Cu")
		(net "GND")
	)
	(segment
		(start 311.882282 -291.666676)
		(end 312.987182 -291.666676)
		(width 0.381)
		(layer "F.Cu")
		(net "GND")
	)
	(segment
		(start 398.446752 -8.320024)
		(end 398.446752 -9.424924)
		(width 0.3556)
		(layer "F.Cu")
		(net "GND")
	)
	(segment
		(start 254.975614 -295.06672)
		(end 256.080514 -295.06672)
		(width 0.381)
		(layer "F.Cu")
		(net "GND")
	)
	(segment
		(start 159.918146 -234.716574)
		(end 158.813246 -234.716574)
		(width 0.381)
		(layer "F.Cu")
		(net "GND")
	)
	(segment
		(start 432.379882 -277.216616)
		(end 433.484782 -277.216616)
		(width 0.381)
		(layer "F.Cu")
		(net "GND")
	)
	(segment
		(start 342.190578 -48.920146)
		(end 342.19134 -48.920146)
		(width 0.254)
		(layer "F.Cu")
		(net "GND")
	)
	(segment
		(start 305.443382 -200.716642)
		(end 306.548282 -200.716642)
		(width 0.381)
		(layer "F.Cu")
		(net "GND")
	)
	(segment
		(start 20.889214 -305.266598)
		(end 19.784314 -305.266598)
		(width 0.381)
		(layer "F.Cu")
		(net "GND")
	)
	(segment
		(start 370.85778 -216.78646)
		(end 370.85778 -216.250774)
		(width 0.254)
		(layer "F.Cu")
		(net "GND")
	)
	(segment
		(start 7.035546 -295.06672)
		(end 8.140446 -295.06672)
		(width 0.381)
		(layer "F.Cu")
		(net "GND")
	)
	(segment
		(start 88.615266 -217.06459)
		(end 88.615012 -217.064336)
		(width 0.2032)
		(layer "F.Cu")
		(net "GND")
	)
	(segment
		(start 294.904414 -285.716726)
		(end 293.799514 -285.716726)
		(width 0.381)
		(layer "F.Cu")
		(net "GND")
	)
	(segment
		(start 197.637146 -272.116804)
		(end 196.532246 -272.116804)
		(width 0.381)
		(layer "F.Cu")
		(net "GND")
	)
	(segment
		(start 43.520614 -230.466646)
		(end 42.415714 -230.466646)
		(width 0.381)
		(layer "F.Cu")
		(net "GND")
	)
	(segment
		(start 439.923682 -232.166668)
		(end 441.028582 -232.166668)
		(width 0.381)
		(layer "F.Cu")
		(net "GND")
	)
	(segment
		(start 170.457114 -249.166634)
		(end 171.562014 -249.166634)
		(width 0.381)
		(layer "F.Cu")
		(net "GND")
	)
	(segment
		(start 366.15878 -226.017582)
		(end 366.159034 -226.017328)
		(width 0.254)
		(layer "F.Cu")
		(net "GND")
	)
	(segment
		(start 337.49488 -240.388902)
		(end 337.49488 -239.853216)
		(width 0.2032)
		(layer "F.Cu")
		(net "GND")
	)
	(segment
		(start 422.497504 -130.944874)
		(end 422.497504 -131.575302)
		(width 0.381)
		(layer "F.Cu")
		(net "GND")
	)
	(segment
		(start 351.71253 -361.961938)
		(end 351.806764 -361.867704)
		(width 0.381)
		(layer "F.Cu")
		(net "GND")
	)
	(segment
		(start 352.171762 -278.336248)
		(end 352.172016 -278.336502)
		(width 0.2032)
		(layer "F.Cu")
		(net "GND")
	)
	(segment
		(start 57.503314 -282.316682)
		(end 58.608214 -282.316682)
		(width 0.381)
		(layer "F.Cu")
		(net "GND")
	)
	(segment
		(start 347.36278 -231.436418)
		(end 347.363034 -231.436164)
		(width 0.2032)
		(layer "F.Cu")
		(net "GND")
	)
	(segment
		(start 272.273014 -296.766742)
		(end 271.168114 -296.766742)
		(width 0.381)
		(layer "F.Cu")
		(net "GND")
	)
	(segment
		(start 215.719914 -194.766692)
		(end 216.824814 -194.766692)
		(width 0.381)
		(layer "F.Cu")
		(net "GND")
	)
	(segment
		(start 438.2516 -94.503748)
		(end 438.427876 -94.327472)
		(width 0.3556)
		(layer "F.Cu")
		(net "GND")
	)
	(segment
		(start 29.666946 -234.716574)
		(end 30.771846 -234.716574)
		(width 0.381)
		(layer "F.Cu")
		(net "GND")
	)
	(segment
		(start 92.954094 -278.336248)
		(end 92.954348 -278.336502)
		(width 0.2032)
		(layer "F.Cu")
		(net "GND")
	)
	(segment
		(start 88.255094 -279.428194)
		(end 88.255094 -279.964134)
		(width 0.2032)
		(layer "F.Cu")
		(net "GND")
	)
	(segment
		(start 127.726694 -268.033754)
		(end 127.726948 -268.569694)
		(width 0.2032)
		(layer "F.Cu")
		(net "GND")
	)
	(segment
		(start 68.485766 -112.70869)
		(end 69.095366 -112.70869)
		(width 0.381)
		(layer "F.Cu")
		(net "GND")
	)
	(segment
		(start 53.07457 -153.725626)
		(end 52.72913 -153.380186)
		(width 0.2032)
		(layer "F.Cu")
		(net "GND")
	)
	(segment
		(start 336.085434 -244.458744)
		(end 336.085434 -243.922804)
		(width 0.2032)
		(layer "F.Cu")
		(net "GND")
	)
	(segment
		(start 106.941112 -220.041978)
		(end 106.941366 -220.041724)
		(width 0.254)
		(layer "F.Cu")
		(net "GND")
	)
	(segment
		(start 113.989866 -217.600276)
		(end 113.989866 -217.064336)
		(width 0.254)
		(layer "F.Cu")
		(net "GND")
	)
	(segment
		(start 107.051094 -283.219652)
		(end 107.051348 -283.219906)
		(width 0.254)
		(layer "F.Cu")
		(net "GND")
	)
	(segment
		(start 180.339746 -251.716794)
		(end 181.444646 -251.716794)
		(width 0.381)
		(layer "F.Cu")
		(net "GND")
	)
	(segment
		(start 108.820712 -233.064304)
		(end 108.820712 -232.528618)
		(width 0.254)
		(layer "F.Cu")
		(net "GND")
	)
	(segment
		(start 307.782214 -298.466764)
		(end 308.887114 -298.466764)
		(width 0.381)
		(layer "F.Cu")
		(net "GND")
	)
	(segment
		(start 57.503314 -216.866724)
		(end 58.608214 -216.866724)
		(width 0.381)
		(layer "F.Cu")
		(net "GND")
	)
	(segment
		(start 99.532694 -258.2672)
		(end 99.532694 -258.802886)
		(width 0.2032)
		(layer "F.Cu")
		(net "GND")
	)
	(segment
		(start 272.273014 -221.96679)
		(end 271.168114 -221.96679)
		(width 0.381)
		(layer "F.Cu")
		(net "GND")
	)
	(segment
		(start 39.165022 -354.022914)
		(end 38.83787 -354.022914)
		(width 0.2032)
		(layer "F.Cu")
		(net "GND")
	)
	(segment
		(start 103.762048 -263.96442)
		(end 103.762048 -264.500106)
		(width 0.254)
		(layer "F.Cu")
		(net "GND")
	)
	(segment
		(start 106.111294 -276.172676)
		(end 106.111294 -276.708616)
		(width 0.2032)
		(layer "F.Cu")
		(net "GND")
	)
	(segment
		(start 178.000914 -261.066788)
		(end 176.896014 -261.066788)
		(width 0.381)
		(layer "F.Cu")
		(net "GND")
	)
	(segment
		(start 195.427346 -204.96657)
		(end 196.532246 -204.96657)
		(width 0.381)
		(layer "F.Cu")
		(net "GND")
	)
	(segment
		(start 11.135614 -219.41663)
		(end 12.240514 -219.41663)
		(width 0.381)
		(layer "F.Cu")
		(net "GND")
	)
	(segment
		(start 135.135112 -226.017582)
		(end 135.135366 -226.017328)
		(width 0.254)
		(layer "F.Cu")
		(net "GND")
	)
	(segment
		(start 59.842146 -261.916672)
		(end 60.947046 -261.916672)
		(width 0.381)
		(layer "F.Cu")
		(net "GND")
	)
	(segment
		(start 361.92968 -238.76127)
		(end 361.92968 -238.225584)
		(width 0.254)
		(layer "F.Cu")
		(net "GND")
	)
	(segment
		(start 134.665212 -245.272306)
		(end 134.665212 -244.73662)
		(width 0.2032)
		(layer "F.Cu")
		(net "GND")
	)
	(segment
		(start 44.754546 -229.616762)
		(end 45.859446 -229.616762)
		(width 0.381)
		(layer "F.Cu")
		(net "GND")
	)
	(segment
		(start 354.991162 -274.54479)
		(end 354.991162 -275.080476)
		(width 0.254)
		(layer "F.Cu")
		(net "GND")
	)
	(segment
		(start 445.760602 -78.229968)
		(end 445.760602 -78.861412)
		(width 0.381)
		(layer "F.Cu")
		(net "GND")
	)
	(segment
		(start 191.983614 -280.61666)
		(end 193.088514 -280.61666)
		(width 0.381)
		(layer "F.Cu")
		(net "GND")
	)
	(segment
		(start 97.073466 -240.389156)
		(end 97.073466 -239.853216)
		(width 0.2032)
		(layer "F.Cu")
		(net "GND")
	)
	(segment
		(start 256.080514 -216.016586)
		(end 257.185414 -216.016586)
		(width 0.381)
		(layer "F.Cu")
		(net "GND")
	)
	(segment
		(start 414.297114 -195.616576)
		(end 415.402014 -195.616576)
		(width 0.381)
		(layer "F.Cu")
		(net "GND")
	)
	(segment
		(start 98.953066 -224.111566)
		(end 98.953066 -223.575626)
		(width 0.2032)
		(layer "F.Cu")
		(net "GND")
	)
	(segment
		(start 376.49658 -247.714262)
		(end 376.496834 -247.714008)
		(width 0.2032)
		(layer "F.Cu")
		(net "GND")
	)
	(segment
		(start 266.619482 -204.116686)
		(end 267.724382 -204.116686)
		(width 0.381)
		(layer "F.Cu")
		(net "GND")
	)
	(segment
		(start 429.384714 -317.166752)
		(end 430.489614 -317.166752)
		(width 0.381)
		(layer "F.Cu")
		(net "GND")
	)
	(segment
		(start 277.607014 -265.316716)
		(end 278.711914 -265.316716)
		(width 0.381)
		(layer "F.Cu")
		(net "GND")
	)
	(segment
		(start 186.649614 -314.616592)
		(end 185.544714 -314.616592)
		(width 0.381)
		(layer "F.Cu")
		(net "GND")
	)
	(segment
		(start 449.677282 -316.316614)
		(end 448.572382 -316.316614)
		(width 0.381)
		(layer "F.Cu")
		(net "GND")
	)
	(segment
		(start 432.379882 -272.966688)
		(end 433.484782 -272.966688)
		(width 0.381)
		(layer "F.Cu")
		(net "GND")
	)
	(segment
		(start 181.444646 -306.116736)
		(end 180.339746 -306.116736)
		(width 0.381)
		(layer "F.Cu")
		(net "GND")
	)
	(segment
		(start 396.646908 -8.320024)
		(end 396.646908 -9.424924)
		(width 0.3556)
		(layer "F.Cu")
		(net "GND")
	)
	(segment
		(start 63.942214 -275.516594)
		(end 65.047114 -275.516594)
		(width 0.381)
		(layer "F.Cu")
		(net "GND")
	)
	(segment
		(start 311.882282 -294.216582)
		(end 312.987182 -294.216582)
		(width 0.381)
		(layer "F.Cu")
		(net "GND")
	)
	(segment
		(start 364.82782 -386.730748)
		(end 364.82782 -386.372608)
		(width 0.3556)
		(layer "F.Cu")
		(net "GND")
	)
	(segment
		(start 378.956316 -264.499852)
		(end 378.956062 -264.500106)
		(width 0.2032)
		(layer "F.Cu")
		(net "GND")
	)
	(segment
		(start 373.317516 -286.7533)
		(end 373.317516 -287.288986)
		(width 0.254)
		(layer "F.Cu")
		(net "GND")
	)
	(segment
		(start 113.269776 -92.583762)
		(end 113.269776 -92.329762)
		(width 0.3556)
		(layer "F.Cu")
		(net "GND")
	)
	(segment
		(start 118.328948 -270.167862)
		(end 118.328948 -270.19758)
		(width 0.254)
		(layer "F.Cu")
		(net "GND")
	)
	(segment
		(start 354.051362 -276.172676)
		(end 354.051362 -276.708616)
		(width 0.2032)
		(layer "F.Cu")
		(net "GND")
	)
	(segment
		(start 186.649614 -294.216582)
		(end 185.544714 -294.216582)
		(width 0.381)
		(layer "F.Cu")
		(net "GND")
	)
	(segment
		(start 12.240514 -230.466646)
		(end 13.345414 -230.466646)
		(width 0.381)
		(layer "F.Cu")
		(net "GND")
	)
	(segment
		(start 210.514946 -197.316598)
		(end 211.619846 -197.316598)
		(width 0.381)
		(layer "F.Cu")
		(net "GND")
	)
	(segment
		(start 138.424666 -230.622602)
		(end 137.954766 -230.900478)
		(width 0.254)
		(layer "F.Cu")
		(net "GND")
	)
	(segment
		(start 26.596594 -404.345394)
		(end 27.131772 -404.345394)
		(width 0.3556)
		(layer "F.Cu")
		(net "GND")
	)
	(segment
		(start 356.76078 -220.041978)
		(end 356.761034 -220.041724)
		(width 0.254)
		(layer "F.Cu")
		(net "GND")
	)
	(segment
		(start 132.895848 -286.7533)
		(end 132.895848 -287.288986)
		(width 0.254)
		(layer "F.Cu")
		(net "GND")
	)
	(segment
		(start 342.19388 -238.76127)
		(end 342.19388 -238.225584)
		(width 0.2032)
		(layer "F.Cu")
		(net "GND")
	)
	(segment
		(start 278.711914 -313.766708)
		(end 279.816814 -313.766708)
		(width 0.381)
		(layer "F.Cu")
		(net "GND")
	)
	(segment
		(start 293.799514 -216.016586)
		(end 294.904414 -216.016586)
		(width 0.381)
		(layer "F.Cu")
		(net "GND")
	)
	(segment
		(start 346.063316 -260.708902)
		(end 346.063316 -261.244588)
		(width 0.2032)
		(layer "F.Cu")
		(net "GND")
	)
	(segment
		(start 344.63355 -45.630846)
		(end 344.363294 -45.160692)
		(width 0.254)
		(layer "F.Cu")
		(net "GND")
	)
	(segment
		(start 122.917712 -222.76181)
		(end 122.917966 -222.761556)
		(width 0.254)
		(layer "F.Cu")
		(net "GND")
	)
	(segment
		(start 48.854614 -316.316614)
		(end 49.959514 -316.316614)
		(width 0.381)
		(layer "F.Cu")
		(net "GND")
	)
	(segment
		(start 409.482798 -312.892948)
		(end 409.558998 -312.892948)
		(width 0.381)
		(layer "F.Cu")
		(net "GND")
	)
	(segment
		(start 105.641648 -276.986492)
		(end 105.641648 -277.521924)
		(width 0.2032)
		(layer "F.Cu")
		(net "GND")
	)
	(segment
		(start 462.555082 -196.466714)
		(end 463.659982 -196.466714)
		(width 0.381)
		(layer "F.Cu")
		(net "GND")
	)
	(segment
		(start 344.63355 -43.751246)
		(end 344.363294 -43.281092)
		(width 0.254)
		(layer "F.Cu")
		(net "GND")
	)
	(segment
		(start 372.377716 -287.288986)
		(end 372.377462 -287.28924)
		(width 0.254)
		(layer "F.Cu")
		(net "GND")
	)
	(segment
		(start 181.444646 -279.766776)
		(end 182.549546 -279.766776)
		(width 0.381)
		(layer "F.Cu")
		(net "GND")
	)
	(segment
		(start 108.461048 -272.103342)
		(end 108.461048 -272.639028)
		(width 0.2032)
		(layer "F.Cu")
		(net "GND")
	)
	(segment
		(start 131.956048 -257.45313)
		(end 131.956048 -257.98907)
		(width 0.2032)
		(layer "F.Cu")
		(net "GND")
	)
	(segment
		(start 20.889214 -194.766692)
		(end 19.784314 -194.766692)
		(width 0.381)
		(layer "F.Cu")
		(net "GND")
	)
	(segment
		(start 45.859446 -290.816792)
		(end 46.964346 -290.816792)
		(width 0.381)
		(layer "F.Cu")
		(net "GND")
	)
	(segment
		(start 278.711914 -304.416714)
		(end 277.607014 -304.416714)
		(width 0.381)
		(layer "F.Cu")
		(net "GND")
	)
	(segment
		(start 165.252146 -292.516814)
		(end 166.357046 -292.516814)
		(width 0.381)
		(layer "F.Cu")
		(net "GND")
	)
	(segment
		(start 312.4835 -22.7203)
		(end 309.99684 -20.23364)
		(width 0.3556)
		(layer "F.Cu")
		(net "GND")
	)
	(segment
		(start 44.754546 -217.716608)
		(end 45.859446 -217.716608)
		(width 0.381)
		(layer "F.Cu")
		(net "GND")
	)
	(segment
		(start 271.168114 -246.616728)
		(end 270.063214 -246.616728)
		(width 0.381)
		(layer "F.Cu")
		(net "GND")
	)
	(segment
		(start 202.971146 -240.666778)
		(end 204.076046 -240.666778)
		(width 0.381)
		(layer "F.Cu")
		(net "GND")
	)
	(segment
		(start 118.804944 -74.631042)
		(end 118.169944 -74.631042)
		(width 0.3556)
		(layer "F.Cu")
		(net "GND")
	)
	(segment
		(start 98.123248 -287.288986)
		(end 98.122994 -287.28924)
		(width 0.254)
		(layer "F.Cu")
		(net "GND")
	)
	(segment
		(start 305.270154 -434.69814)
		(end 305.270154 -435.20741)
		(width 0.3556)
		(layer "F.Cu")
		(net "GND")
	)
	(segment
		(start 464.764882 -305.266598)
		(end 463.659982 -305.266598)
		(width 0.381)
		(layer "F.Cu")
		(net "GND")
	)
	(segment
		(start 87.315294 -264.778236)
		(end 87.315294 -265.314176)
		(width 0.2032)
		(layer "F.Cu")
		(net "GND")
	)
	(segment
		(start 196.532246 -233.016806)
		(end 197.637146 -233.016806)
		(width 0.381)
		(layer "F.Cu")
		(net "GND")
	)
	(segment
		(start 132.895848 -281.869896)
		(end 132.895594 -282.405836)
		(width 0.254)
		(layer "F.Cu")
		(net "GND")
	)
	(segment
		(start 262.519414 -223.666558)
		(end 263.624314 -223.666558)
		(width 0.381)
		(layer "F.Cu")
		(net "GND")
	)
	(segment
		(start 343.243916 -284.033468)
		(end 343.243662 -284.033722)
		(width 0.254)
		(layer "F.Cu")
		(net "GND")
	)
	(segment
		(start 90.604848 -272.103342)
		(end 90.604848 -272.639282)
		(width 0.2032)
		(layer "F.Cu")
		(net "GND")
	)
	(segment
		(start 379.896116 -267.219938)
		(end 379.896116 -267.755878)
		(width 0.2032)
		(layer "F.Cu")
		(net "GND")
	)
	(segment
		(start 378.956316 -273.730974)
		(end 378.956062 -274.266914)
		(width 0.2032)
		(layer "F.Cu")
		(net "GND")
	)
	(segment
		(start 48.854614 -299.316648)
		(end 49.959514 -299.316648)
		(width 0.381)
		(layer "F.Cu")
		(net "GND")
	)
	(segment
		(start 92.954348 -266.406122)
		(end 92.954348 -266.941808)
		(width 0.2032)
		(layer "F.Cu")
		(net "GND")
	)
	(segment
		(start 460.664814 -227.066602)
		(end 459.559914 -227.066602)
		(width 0.381)
		(layer "F.Cu")
		(net "GND")
	)
	(segment
		(start 375.557034 -249.341894)
		(end 375.557034 -248.806208)
		(width 0.2032)
		(layer "F.Cu")
		(net "GND")
	)
	(segment
		(start 380.365762 -253.383796)
		(end 380.365762 -253.919736)
		(width 0.2032)
		(layer "F.Cu")
		(net "GND")
	)
	(segment
		(start 122.087894 -274.54479)
		(end 122.088148 -275.08073)
		(width 0.2032)
		(layer "F.Cu")
		(net "GND")
	)
	(segment
		(start 137.014966 -247.714008)
		(end 137.014966 -247.178322)
		(width 0.2032)
		(layer "F.Cu")
		(net "GND")
	)
	(segment
		(start 294.904414 -201.56678)
		(end 293.799514 -201.56678)
		(width 0.381)
		(layer "F.Cu")
		(net "GND")
	)
	(segment
		(start 304.338482 -232.166668)
		(end 305.443382 -232.166668)
		(width 0.381)
		(layer "F.Cu")
		(net "GND")
	)
	(segment
		(start 94.833694 -253.383796)
		(end 95.30334 -253.10592)
		(width 0.2032)
		(layer "F.Cu")
		(net "GND")
	)
	(segment
		(start 410.878274 -235.591604)
		(end 410.853382 -235.566712)
		(width 0.381)
		(layer "F.Cu")
		(net "GND")
	)
	(segment
		(start 380.365762 -282.683966)
		(end 380.365762 -283.219906)
		(width 0.254)
		(layer "F.Cu")
		(net "GND")
	)
	(segment
		(start 271.168114 -236.416596)
		(end 270.063214 -236.416596)
		(width 0.381)
		(layer "F.Cu")
		(net "GND")
	)
	(segment
		(start 170.457114 -250.866656)
		(end 171.562014 -250.866656)
		(width 0.381)
		(layer "F.Cu")
		(net "GND")
	)
	(segment
		(start 53.07457 -162.713924)
		(end 53.07457 -162.361626)
		(width 0.2032)
		(layer "F.Cu")
		(net "GND")
	)
	(segment
		(start 384.124962 -266.405868)
		(end 384.124962 -266.941808)
		(width 0.254)
		(layer "F.Cu")
		(net "GND")
	)
	(segment
		(start 294.302434 -423.56532)
		(end 294.691562 -423.954448)
		(width 0.3556)
		(layer "F.Cu")
		(net "GND")
	)
	(segment
		(start 29.346906 -8.320024)
		(end 29.346906 -9.424924)
		(width 0.3556)
		(layer "F.Cu")
		(net "GND")
	)
	(segment
		(start 181.444646 -301.866808)
		(end 180.339746 -301.866808)
		(width 0.381)
		(layer "F.Cu")
		(net "GND")
	)
	(segment
		(start 18.679414 -299.316648)
		(end 19.784314 -299.316648)
		(width 0.381)
		(layer "F.Cu")
		(net "GND")
	)
	(segment
		(start 182.549546 -317.166752)
		(end 181.444646 -317.166752)
		(width 0.381)
		(layer "F.Cu")
		(net "GND")
	)
	(segment
		(start 339.014562 -276.172676)
		(end 339.014562 -276.708616)
		(width 0.2032)
		(layer "F.Cu")
		(net "GND")
	)
	(segment
		(start 342.66378 -246.08663)
		(end 342.664034 -246.086376)
		(width 0.2032)
		(layer "F.Cu")
		(net "GND")
	)
	(segment
		(start 311.882282 -278.916638)
		(end 312.987182 -278.916638)
		(width 0.381)
		(layer "F.Cu")
		(net "GND")
	)
	(segment
		(start 103.762048 -275.35886)
		(end 103.762048 -275.894546)
		(width 0.2032)
		(layer "F.Cu")
		(net "GND")
	)
	(segment
		(start 372.377716 -261.244588)
		(end 372.377462 -261.244842)
		(width 0.2032)
		(layer "F.Cu")
		(net "GND")
	)
	(segment
		(start 260.180582 -294.216582)
		(end 259.075682 -294.216582)
		(width 0.381)
		(layer "F.Cu")
		(net "GND")
	)
	(segment
		(start 278.711914 -250.016772)
		(end 279.816814 -250.016772)
		(width 0.381)
		(layer "F.Cu")
		(net "GND")
	)
	(segment
		(start 305.58994 -430.26965)
		(end 305.58994 -429.632618)
		(width 0.3556)
		(layer "F.Cu")
		(net "GND")
	)
	(segment
		(start 384.015234 -226.017328)
		(end 384.015234 -226.553268)
		(width 0.254)
		(layer "F.Cu")
		(net "GND")
	)
	(segment
		(start 24.926036 -183.515254)
		(end 25.10155 -183.33974)
		(width 0.3556)
		(layer "F.Cu")
		(net "GND")
	)
	(segment
		(start 179.105814 -224.516696)
		(end 178.000914 -224.516696)
		(width 0.381)
		(layer "F.Cu")
		(net "GND")
	)
	(segment
		(start 19.784314 -244.066568)
		(end 18.679414 -244.066568)
		(width 0.381)
		(layer "F.Cu")
		(net "GND")
	)
	(segment
		(start 261.285482 -289.966654)
		(end 260.180582 -289.966654)
		(width 0.381)
		(layer "F.Cu")
		(net "GND")
	)
	(segment
		(start 100.942648 -283.497782)
		(end 100.942648 -284.033468)
		(width 0.254)
		(layer "F.Cu")
		(net "GND")
	)
	(segment
		(start 33.767014 -258.516628)
		(end 34.871914 -258.516628)
		(width 0.381)
		(layer "F.Cu")
		(net "GND")
	)
	(segment
		(start 418.397182 -286.56661)
		(end 417.292282 -286.56661)
		(width 0.381)
		(layer "F.Cu")
		(net "GND")
	)
	(segment
		(start 56.398414 -316.316614)
		(end 57.503314 -316.316614)
		(width 0.381)
		(layer "F.Cu")
		(net "GND")
	)
	(segment
		(start 94.9452 -101.759512)
		(end 94.250764 -101.759512)
		(width 0.3556)
		(layer "F.Cu")
		(net "GND")
	)
	(segment
		(start 178.000914 -238.116618)
		(end 176.896014 -238.116618)
		(width 0.381)
		(layer "F.Cu")
		(net "GND")
	)
	(segment
		(start 374.275858 -421.125396)
		(end 375.04878 -421.125396)
		(width 0.3556)
		(layer "F.Cu")
		(net "GND")
	)
	(segment
		(start 124.327666 -238.761524)
		(end 124.327412 -238.76127)
		(width 0.2032)
		(layer "F.Cu")
		(net "GND")
	)
	(segment
		(start 432.379882 -219.41663)
		(end 433.484782 -219.41663)
		(width 0.381)
		(layer "F.Cu")
		(net "GND")
	)
	(segment
		(start 292.929056 -50.141378)
		(end 292.332156 -50.141378)
		(width 0.3556)
		(layer "F.Cu")
		(net "GND")
	)
	(segment
		(start 208.176114 -267.866622)
		(end 209.281014 -267.866622)
		(width 0.381)
		(layer "F.Cu")
		(net "GND")
	)
	(segment
		(start 457.221082 -224.516696)
		(end 456.116182 -224.516696)
		(width 0.381)
		(layer "F.Cu")
		(net "GND")
	)
	(segment
		(start 267.724382 -244.066568)
		(end 268.829282 -244.066568)
		(width 0.381)
		(layer "F.Cu")
		(net "GND")
	)
	(segment
		(start 44.754546 -225.36658)
		(end 45.859446 -225.36658)
		(width 0.381)
		(layer "F.Cu")
		(net "GND")
	)
	(segment
		(start 419.502082 -267.866622)
		(end 418.397182 -267.866622)
		(width 0.381)
		(layer "F.Cu")
		(net "GND")
	)
	(segment
		(start 289.250882 -221.116652)
		(end 290.355782 -221.116652)
		(width 0.381)
		(layer "F.Cu")
		(net "GND")
	)
	(segment
		(start 108.820712 -229.808786)
		(end 108.820966 -229.808532)
		(width 0.2032)
		(layer "F.Cu")
		(net "GND")
	)
	(segment
		(start 453.121014 -240.666778)
		(end 452.016114 -240.666778)
		(width 0.381)
		(layer "F.Cu")
		(net "GND")
	)
	(segment
		(start 303.923954 -33.472882)
		(end 304.197258 -33.746186)
		(width 0.3556)
		(layer "F.Cu")
		(net "GND")
	)
	(segment
		(start 420.736014 -246.616728)
		(end 421.840914 -246.616728)
		(width 0.381)
		(layer "F.Cu")
		(net "GND")
	)
	(segment
		(start 339.374734 -217.600276)
		(end 339.374734 -217.064336)
		(width 0.2032)
		(layer "F.Cu")
		(net "GND")
	)
	(segment
		(start 459.559914 -258.516628)
		(end 458.455014 -258.516628)
		(width 0.381)
		(layer "F.Cu")
		(net "GND")
	)
	(segment
		(start 311.666382 -284.866588)
		(end 312.987182 -284.866588)
		(width 0.381)
		(layer "F.Cu")
		(net "GND")
	)
	(segment
		(start 109.38637 -14.332458)
		(end 109.744764 -13.974064)
		(width 0.3556)
		(layer "F.Cu")
		(net "GND")
	)
	(segment
		(start 110.230666 -246.900446)
		(end 110.230666 -246.365014)
		(width 0.254)
		(layer "F.Cu")
		(net "GND")
	)
	(segment
		(start 452.016114 -283.166566)
		(end 450.911214 -283.166566)
		(width 0.381)
		(layer "F.Cu")
		(net "GND")
	)
	(segment
		(start 87.785194 -260.708902)
		(end 87.785194 -261.244842)
		(width 0.254)
		(layer "F.Cu")
		(net "GND")
	)
	(segment
		(start 15.684246 -231.316784)
		(end 16.789146 -231.316784)
		(width 0.381)
		(layer "F.Cu")
		(net "GND")
	)
	(segment
		(start 358.280716 -259.081016)
		(end 358.280716 -259.616702)
		(width 0.254)
		(layer "F.Cu")
		(net "GND")
	)
	(segment
		(start 345.483434 -220.041724)
		(end 345.483434 -219.506038)
		(width 0.254)
		(layer "F.Cu")
		(net "GND")
	)
	(segment
		(start 362.979716 -273.730974)
		(end 362.979462 -274.266914)
		(width 0.254)
		(layer "F.Cu")
		(net "GND")
	)
	(segment
		(start 276.373082 -207.51673)
		(end 275.268182 -207.51673)
		(width 0.381)
		(layer "F.Cu")
		(net "GND")
	)
	(segment
		(start 379.31598 -216.250774)
		(end 379.316234 -216.25052)
		(width 0.254)
		(layer "F.Cu")
		(net "GND")
	)
	(segment
		(start 373.207534 -235.506006)
		(end 373.207534 -234.970066)
		(width 0.2032)
		(layer "F.Cu")
		(net "GND")
	)
	(segment
		(start 113.349532 -365.558324)
		(end 113.349532 -366.167924)
		(width 0.381)
		(layer "F.Cu")
		(net "GND")
	)
	(segment
		(start 372.26748 -228.994716)
		(end 372.26748 -228.45903)
		(width 0.254)
		(layer "F.Cu")
		(net "GND")
	)
	(segment
		(start 38.315646 -263.616694)
		(end 37.210746 -263.616694)
		(width 0.381)
		(layer "F.Cu")
		(net "GND")
	)
	(segment
		(start 309.123588 -37.822886)
		(end 308.501542 -37.822886)
		(width 0.3556)
		(layer "F.Cu")
		(net "GND")
	)
	(segment
		(start 335.14538 -247.178576)
		(end 335.145634 -247.178322)
		(width 0.2032)
		(layer "F.Cu")
		(net "GND")
	)
	(segment
		(start 281.707082 -196.466714)
		(end 282.811982 -196.466714)
		(width 0.381)
		(layer "F.Cu")
		(net "GND")
	)
	(segment
		(start 463.659982 -275.516594)
		(end 462.555082 -275.516594)
		(width 0.381)
		(layer "F.Cu")
		(net "GND")
	)
	(segment
		(start 405.648414 -311.216802)
		(end 406.753314 -311.216802)
		(width 0.381)
		(layer "F.Cu")
		(net "GND")
	)
	(segment
		(start 414.297114 -229.616762)
		(end 415.402014 -229.616762)
		(width 0.381)
		(layer "F.Cu")
		(net "GND")
	)
	(segment
		(start 421.840914 -234.716574)
		(end 422.945814 -234.716574)
		(width 0.381)
		(layer "F.Cu")
		(net "GND")
	)
	(segment
		(start 334.205834 -234.69219)
		(end 334.67548 -234.970066)
		(width 0.2032)
		(layer "F.Cu")
		(net "GND")
	)
	(segment
		(start 147.797774 -51.404012)
		(end 147.188174 -51.404012)
		(width 0.3556)
		(layer "F.Cu")
		(net "GND")
	)
	(segment
		(start 467.08314 -46.408848)
		(end 467.08314 -47.186088)
		(width 0.3556)
		(layer "F.Cu")
		(net "GND")
	)
	(segment
		(start 38.315646 -225.36658)
		(end 37.210746 -225.36658)
		(width 0.381)
		(layer "F.Cu")
		(net "GND")
	)
	(segment
		(start 212.724746 -201.56678)
		(end 211.619846 -201.56678)
		(width 0.381)
		(layer "F.Cu")
		(net "GND")
	)
	(segment
		(start 418.397182 -244.066568)
		(end 417.292282 -244.066568)
		(width 0.381)
		(layer "F.Cu")
		(net "GND")
	)
	(segment
		(start 123.497848 -262.336534)
		(end 123.497848 -262.87222)
		(width 0.254)
		(layer "F.Cu")
		(net "GND")
	)
	(segment
		(start 200.632314 -245.76659)
		(end 201.737214 -245.76659)
		(width 0.381)
		(layer "F.Cu")
		(net "GND")
	)
	(segment
		(start 421.840914 -240.666778)
		(end 422.945814 -240.666778)
		(width 0.381)
		(layer "F.Cu")
		(net "GND")
	)
	(segment
		(start 413.418274 -363.912658)
		(end 413.760412 -363.912658)
		(width 0.2032)
		(layer "F.Cu")
		(net "GND")
	)
	(segment
		(start 44.754546 -244.916706)
		(end 45.859446 -244.916706)
		(width 0.381)
		(layer "F.Cu")
		(net "GND")
	)
	(segment
		(start 340.894162 -289.195002)
		(end 340.894162 -289.807142)
		(width 0.2032)
		(layer "F.Cu")
		(net "GND")
	)
	(segment
		(start 275.268182 -291.666676)
		(end 274.163282 -291.666676)
		(width 0.381)
		(layer "F.Cu")
		(net "GND")
	)
	(segment
		(start 421.840914 -210.916774)
		(end 422.945814 -210.916774)
		(width 0.381)
		(layer "F.Cu")
		(net "GND")
	)
	(segment
		(start 410.853382 -221.116652)
		(end 411.958282 -221.116652)
		(width 0.381)
		(layer "F.Cu")
		(net "GND")
	)
	(segment
		(start 57.503314 -267.866622)
		(end 56.398414 -267.866622)
		(width 0.381)
		(layer "F.Cu")
		(net "GND")
	)
	(segment
		(start 279.816814 -295.06672)
		(end 278.711914 -295.06672)
		(width 0.381)
		(layer "F.Cu")
		(net "GND")
	)
	(segment
		(start 386.364734 -220.855794)
		(end 386.364734 -220.319854)
		(width 0.254)
		(layer "F.Cu")
		(net "GND")
	)
	(segment
		(start 289.250882 -264.466578)
		(end 290.355782 -264.466578)
		(width 0.381)
		(layer "F.Cu")
		(net "GND")
	)
	(segment
		(start 39.420546 -307.816758)
		(end 38.315646 -307.816758)
		(width 0.381)
		(layer "F.Cu")
		(net "GND")
	)
	(segment
		(start 91.074748 -268.034008)
		(end 91.074748 -268.569694)
		(width 0.2032)
		(layer "F.Cu")
		(net "GND")
	)
	(segment
		(start 448.572382 -219.41663)
		(end 447.467482 -219.41663)
		(width 0.381)
		(layer "F.Cu")
		(net "GND")
	)
	(segment
		(start 304.338482 -316.316614)
		(end 305.443382 -316.316614)
		(width 0.381)
		(layer "F.Cu")
		(net "GND")
	)
	(segment
		(start 380.835916 -255.825498)
		(end 380.835916 -256.361184)
		(width 0.254)
		(layer "F.Cu")
		(net "GND")
	)
	(segment
		(start 26.223214 -277.216616)
		(end 27.328114 -277.216616)
		(width 0.381)
		(layer "F.Cu")
		(net "GND")
	)
	(segment
		(start 92.844366 -244.45849)
		(end 92.844366 -243.922804)
		(width 0.2032)
		(layer "F.Cu")
		(net "GND")
	)
	(segment
		(start 34.871914 -247.466612)
		(end 35.976814 -247.466612)
		(width 0.381)
		(layer "F.Cu")
		(net "GND")
	)
	(segment
		(start 368.03838 -220.041978)
		(end 368.038634 -220.041724)
		(width 0.254)
		(layer "F.Cu")
		(net "GND")
	)
	(segment
		(start 428.279814 -304.416714)
		(end 429.384714 -304.416714)
		(width 0.381)
		(layer "F.Cu")
		(net "GND")
	)
	(segment
		(start 286.255714 -240.666778)
		(end 285.150814 -240.666778)
		(width 0.381)
		(layer "F.Cu")
		(net "GND")
	)
	(segment
		(start 374.802146 -342.116156)
		(end 374.802146 -342.764872)
		(width 0.381)
		(layer "F.Cu")
		(net "GND")
	)
	(segment
		(start 178.000914 -280.61666)
		(end 179.105814 -280.61666)
		(width 0.381)
		(layer "F.Cu")
		(net "GND")
	)
	(segment
		(start 409.568396 -216.90457)
		(end 409.637992 -216.90457)
		(width 0.381)
		(layer "F.Cu")
		(net "GND")
	)
	(segment
		(start 116.339112 -223.297496)
		(end 116.339112 -222.76181)
		(width 0.254)
		(layer "F.Cu")
		(net "GND")
	)
	(segment
		(start 8.140446 -281.466798)
		(end 9.245346 -281.466798)
		(width 0.381)
		(layer "F.Cu")
		(net "GND")
	)
	(segment
		(start 120.588024 -338.86013)
		(end 121.199148 -338.86013)
		(width 0.381)
		(layer "F.Cu")
		(net "GND")
	)
	(segment
		(start 8.140446 -258.516628)
		(end 9.245346 -258.516628)
		(width 0.381)
		(layer "F.Cu")
		(net "GND")
	)
	(segment
		(start 371.79758 -216.250774)
		(end 371.797834 -216.25052)
		(width 0.254)
		(layer "F.Cu")
		(net "GND")
	)
	(segment
		(start 134.305294 -276.172676)
		(end 134.305548 -276.708616)
		(width 0.2032)
		(layer "F.Cu")
		(net "GND")
	)
	(segment
		(start 105.061512 -226.017582)
		(end 105.061766 -226.017328)
		(width 0.254)
		(layer "F.Cu")
		(net "GND")
	)
	(segment
		(start 113.519712 -243.923566)
		(end 113.52022 -243.923058)
		(width 0.254)
		(layer "F.Cu")
		(net "GND")
	)
	(segment
		(start 302.575214 -423.16019)
		(end 302.575214 -423.79392)
		(width 0.3556)
		(layer "F.Cu")
		(net "GND")
	)
	(segment
		(start 134.775448 -281.869896)
		(end 134.775448 -282.405836)
		(width 0.254)
		(layer "F.Cu")
		(net "GND")
	)
	(segment
		(start 341.364316 -257.988816)
		(end 341.364062 -257.98907)
		(width 0.2032)
		(layer "F.Cu")
		(net "GND")
	)
	(segment
		(start 342.774016 -266.406122)
		(end 342.774016 -266.941808)
		(width 0.2032)
		(layer "F.Cu")
		(net "GND")
	)
	(segment
		(start 355.2698 -406.452578)
		(end 355.2698 -405.8412)
		(width 0.3556)
		(layer "F.Cu")
		(net "GND")
	)
	(segment
		(start 96.133666 -245.27256)
		(end 96.133412 -245.272306)
		(width 0.2032)
		(layer "F.Cu")
		(net "GND")
	)
	(segment
		(start 107.521248 -283.497782)
		(end 107.521248 -284.033468)
		(width 0.254)
		(layer "F.Cu")
		(net "GND")
	)
	(segment
		(start 89.555066 -242.017042)
		(end 89.554812 -242.016788)
		(width 0.2032)
		(layer "F.Cu")
		(net "GND")
	)
	(segment
		(start 262.519414 -238.966756)
		(end 263.624314 -238.966756)
		(width 0.381)
		(layer "F.Cu")
		(net "GND")
	)
	(segment
		(start 346.42298 -247.714262)
		(end 346.42298 -247.178322)
		(width 0.2032)
		(layer "F.Cu")
		(net "GND")
	)
	(segment
		(start 101.83114 -333.125318)
		(end 101.58349 -333.125318)
		(width 0.2032)
		(layer "F.Cu")
		(net "GND")
	)
	(segment
		(start 347.36278 -246.08663)
		(end 347.363034 -246.086376)
		(width 0.2032)
		(layer "F.Cu")
		(net "GND")
	)
	(segment
		(start 254.975614 -315.46673)
		(end 256.080514 -315.46673)
		(width 0.381)
		(layer "F.Cu")
		(net "GND")
	)
	(segment
		(start 90.964512 -216.78646)
		(end 90.964512 -216.250774)
		(width 0.254)
		(layer "F.Cu")
		(net "GND")
	)
	(segment
		(start 113.519712 -222.76181)
		(end 113.519966 -222.761556)
		(width 0.254)
		(layer "F.Cu")
		(net "GND")
	)
	(segment
		(start 196.532246 -278.066754)
		(end 195.427346 -278.066754)
		(width 0.381)
		(layer "F.Cu")
		(net "GND")
	)
	(segment
		(start 168.902634 -353.634802)
		(end 168.902634 -353.168966)
		(width 0.2032)
		(layer "F.Cu")
		(net "GND")
	)
	(segment
		(start 328.834496 -37.209222)
		(end 328.242422 -36.617148)
		(width 0.2032)
		(layer "F.Cu")
		(net "GND")
	)
	(segment
		(start 259.075682 -272.966688)
		(end 260.180582 -272.966688)
		(width 0.381)
		(layer "F.Cu")
		(net "GND")
	)
	(segment
		(start 405.64689 -8.320024)
		(end 405.64689 -9.424924)
		(width 0.3556)
		(layer "F.Cu")
		(net "GND")
	)
	(segment
		(start 91.074494 -285.939484)
		(end 91.074494 -286.475424)
		(width 0.2032)
		(layer "F.Cu")
		(net "GND")
	)
	(segment
		(start 91.434666 -217.600276)
		(end 91.434666 -217.064336)
		(width 0.2032)
		(layer "F.Cu")
		(net "GND")
	)
	(segment
		(start 398.96288 -185.257948)
		(end 398.533874 -185.686954)
		(width 0.3556)
		(layer "F.Cu")
		(net "GND")
	)
	(segment
		(start 463.659982 -266.1666)
		(end 464.764882 -266.1666)
		(width 0.381)
		(layer "F.Cu")
		(net "GND")
	)
	(segment
		(start 106.111294 -282.683966)
		(end 106.111294 -283.219906)
		(width 0.254)
		(layer "F.Cu")
		(net "GND")
	)
	(segment
		(start 113.629694 -255.547622)
		(end 113.629948 -255.547876)
		(width 0.254)
		(layer "F.Cu")
		(net "GND")
	)
	(segment
		(start 374.512332 -57.263792)
		(end 375.121932 -57.263792)
		(width 0.3556)
		(layer "F.Cu")
		(net "GND")
	)
	(segment
		(start 159.918146 -270.416782)
		(end 158.813246 -270.416782)
		(width 0.381)
		(layer "F.Cu")
		(net "GND")
	)
	(segment
		(start 262.519414 -246.616728)
		(end 263.624314 -246.616728)
		(width 0.381)
		(layer "F.Cu")
		(net "GND")
	)
	(segment
		(start 134.195566 -239.57534)
		(end 134.195566 -239.0394)
		(width 0.2032)
		(layer "F.Cu")
		(net "GND")
	)
	(segment
		(start 8.140446 -214.316564)
		(end 9.245346 -214.316564)
		(width 0.381)
		(layer "F.Cu")
		(net "GND")
	)
	(segment
		(start 99.532694 -264.778236)
		(end 99.532694 -265.313922)
		(width 0.2032)
		(layer "F.Cu")
		(net "GND")
	)
	(segment
		(start 134.305294 -281.591512)
		(end 134.305548 -281.591766)
		(width 0.254)
		(layer "F.Cu")
		(net "GND")
	)
	(segment
		(start 214.615014 -264.466578)
		(end 215.719914 -264.466578)
		(width 0.381)
		(layer "F.Cu")
		(net "GND")
	)
	(segment
		(start 307.566314 -273.816572)
		(end 308.887114 -273.816572)
		(width 0.381)
		(layer "F.Cu")
		(net "GND")
	)
	(segment
		(start 337.49488 -243.644674)
		(end 337.49488 -243.108988)
		(width 0.2032)
		(layer "F.Cu")
		(net "GND")
	)
	(segment
		(start 49.959514 -230.466646)
		(end 51.064414 -230.466646)
		(width 0.381)
		(layer "F.Cu")
		(net "GND")
	)
	(segment
		(start 359.58018 -229.808786)
		(end 359.58018 -229.272846)
		(width 0.2032)
		(layer "F.Cu")
		(net "GND")
	)
	(segment
		(start 367.483644 -409.102306)
		(end 367.483644 -408.71521)
		(width 0.3556)
		(layer "F.Cu")
		(net "GND")
	)
	(segment
		(start 92.954094 -289.195002)
		(end 92.954094 -289.807142)
		(width 0.2032)
		(layer "F.Cu")
		(net "GND")
	)
	(segment
		(start 110.340648 -288.381186)
		(end 110.340648 -288.993326)
		(width 0.254)
		(layer "F.Cu")
		(net "GND")
	)
	(segment
		(start 176.896014 -305.266598)
		(end 178.000914 -305.266598)
		(width 0.381)
		(layer "F.Cu")
		(net "GND")
	)
	(segment
		(start 419.502082 -194.766692)
		(end 418.397182 -194.766692)
		(width 0.381)
		(layer "F.Cu")
		(net "GND")
	)
	(segment
		(start 27.328114 -310.366664)
		(end 28.433014 -310.366664)
		(width 0.381)
		(layer "F.Cu")
		(net "GND")
	)
	(segment
		(start 169.062908 -291.666676)
		(end 170.457114 -291.666676)
		(width 0.381)
		(layer "F.Cu")
		(net "GND")
	)
	(segment
		(start 90.604848 -286.7533)
		(end 90.604848 -287.28924)
		(width 0.254)
		(layer "F.Cu")
		(net "GND")
	)
	(segment
		(start 245.66245 -86.35746)
		(end 247.596914 -86.35746)
		(width 0.3556)
		(layer "F.Cu")
		(net "GND")
	)
	(segment
		(start 358.280716 -284.033468)
		(end 358.280462 -284.033722)
		(width 0.254)
		(layer "F.Cu")
		(net "GND")
	)
	(segment
		(start 66.2178 -54.524402)
		(end 66.380614 -54.361588)
		(width 0.3556)
		(layer "F.Cu")
		(net "GND")
	)
	(segment
		(start 158.813246 -227.066602)
		(end 160.212024 -227.066602)
		(width 0.381)
		(layer "F.Cu")
		(net "GND")
	)
	(segment
		(start 215.719914 -269.566644)
		(end 216.824814 -269.566644)
		(width 0.381)
		(layer "F.Cu")
		(net "GND")
	)
	(segment
		(start 312.987182 -258.516628)
		(end 314.092082 -258.516628)
		(width 0.381)
		(layer "F.Cu")
		(net "GND")
	)
	(segment
		(start 335.299558 -46.049946)
		(end 334.899508 -46.449996)
		(width 0.2032)
		(layer "F.Cu")
		(net "GND")
	)
	(segment
		(start 12.240514 -204.116686)
		(end 13.345414 -204.116686)
		(width 0.381)
		(layer "F.Cu")
		(net "GND")
	)
	(segment
		(start 275.268182 -280.61666)
		(end 274.163282 -280.61666)
		(width 0.381)
		(layer "F.Cu")
		(net "GND")
	)
	(segment
		(start 33.767014 -228.766624)
		(end 34.871914 -228.766624)
		(width 0.381)
		(layer "F.Cu")
		(net "GND")
	)
	(segment
		(start 215.719914 -232.166668)
		(end 216.824814 -232.166668)
		(width 0.381)
		(layer "F.Cu")
		(net "GND")
	)
	(segment
		(start 384.595116 -273.730974)
		(end 384.124962 -273.453098)
		(width 0.2032)
		(layer "F.Cu")
		(net "GND")
	)
	(segment
		(start 424.836082 -238.116618)
		(end 425.940982 -238.116618)
		(width 0.381)
		(layer "F.Cu")
		(net "GND")
	)
	(segment
		(start 178.1556 -105.775506)
		(end 178.55565 -105.375456)
		(width 0.3556)
		(layer "F.Cu")
		(net "GND")
	)
	(segment
		(start 435.823614 -229.616762)
		(end 436.928514 -229.616762)
		(width 0.381)
		(layer "F.Cu")
		(net "GND")
	)
	(segment
		(start 275.268182 -289.966654)
		(end 274.163282 -289.966654)
		(width 0.381)
		(layer "F.Cu")
		(net "GND")
	)
	(segment
		(start 336.766408 -54.558946)
		(end 337.306666 -54.558946)
		(width 0.2032)
		(layer "F.Cu")
		(net "GND")
	)
	(segment
		(start 378.956316 -263.96442)
		(end 378.956316 -264.499852)
		(width 0.2032)
		(layer "F.Cu")
		(net "GND")
	)
	(segment
		(start 118.78564 -334.191102)
		(end 118.35765 -333.763112)
		(width 0.2032)
		(layer "F.Cu")
		(net "GND")
	)
	(segment
		(start 173.900846 -216.016586)
		(end 172.795946 -216.016586)
		(width 0.381)
		(layer "F.Cu")
		(net "GND")
	)
	(segment
		(start 260.180582 -224.516696)
		(end 259.075682 -224.516696)
		(width 0.381)
		(layer "F.Cu")
		(net "GND")
	)
	(segment
		(start 363.046518 -359.94975)
		(end 363.656118 -359.94975)
		(width 0.381)
		(layer "F.Cu")
		(net "GND")
	)
	(segment
		(start 39.420546 -236.416596)
		(end 38.315646 -236.416596)
		(width 0.381)
		(layer "F.Cu")
		(net "GND")
	)
	(segment
		(start 202.971146 -217.716608)
		(end 204.076046 -217.716608)
		(width 0.381)
		(layer "F.Cu")
		(net "GND")
	)
	(segment
		(start 368.03838 -221.669864)
		(end 368.03838 -221.133924)
		(width 0.254)
		(layer "F.Cu")
		(net "GND")
	)
	(segment
		(start 94.364048 -261.244588)
		(end 94.363794 -261.244842)
		(width 0.2032)
		(layer "F.Cu")
		(net "GND")
	)
	(segment
		(start 170.457114 -204.116686)
		(end 171.562014 -204.116686)
		(width 0.381)
		(layer "F.Cu")
		(net "GND")
	)
	(segment
		(start 93.424248 -284.033468)
		(end 93.423994 -284.033722)
		(width 0.254)
		(layer "F.Cu")
		(net "GND")
	)
	(segment
		(start 214.615014 -284.866588)
		(end 215.719914 -284.866588)
		(width 0.381)
		(layer "F.Cu")
		(net "GND")
	)
	(segment
		(start 432.379882 -241.516662)
		(end 433.484782 -241.516662)
		(width 0.381)
		(layer "F.Cu")
		(net "GND")
	)
	(segment
		(start 281.707082 -238.116618)
		(end 282.811982 -238.116618)
		(width 0.381)
		(layer "F.Cu")
		(net "GND")
	)
	(segment
		(start 448.572382 -262.76681)
		(end 447.467482 -262.76681)
		(width 0.381)
		(layer "F.Cu")
		(net "GND")
	)
	(segment
		(start 56.398414 -306.96662)
		(end 57.503314 -306.96662)
		(width 0.381)
		(layer "F.Cu")
		(net "GND")
	)
	(segment
		(start 339.374734 -214.344758)
		(end 339.374734 -213.732618)
		(width 0.254)
		(layer "F.Cu")
		(net "GND")
	)
	(segment
		(start 99.422712 -216.78646)
		(end 99.422712 -216.250774)
		(width 0.254)
		(layer "F.Cu")
		(net "GND")
	)
	(segment
		(start 46.467522 -392.183112)
		(end 46.467776 -392.183366)
		(width 0.4572)
		(layer "F.Cu")
		(net "GND")
	)
	(segment
		(start 304.338482 -303.566576)
		(end 305.443382 -303.566576)
		(width 0.381)
		(layer "F.Cu")
		(net "GND")
	)
	(segment
		(start 263.624314 -287.416748)
		(end 264.729214 -287.416748)
		(width 0.381)
		(layer "F.Cu")
		(net "GND")
	)
	(segment
		(start 308.887114 -233.016806)
		(end 309.992014 -233.016806)
		(width 0.381)
		(layer "F.Cu")
		(net "GND")
	)
	(segment
		(start 119.268494 -276.172676)
		(end 119.268494 -276.708616)
		(width 0.2032)
		(layer "F.Cu")
		(net "GND")
	)
	(segment
		(start 127.147066 -217.600276)
		(end 127.147066 -217.064336)
		(width 0.254)
		(layer "F.Cu")
		(net "GND")
	)
	(segment
		(start 177.156364 -334.467962)
		(end 177.156364 -335.483962)
		(width 0.508)
		(layer "F.Cu")
		(net "GND")
	)
	(segment
		(start 87.675466 -232.250488)
		(end 87.675466 -231.714548)
		(width 0.254)
		(layer "F.Cu")
		(net "GND")
	)
	(segment
		(start 297.899582 -316.316614)
		(end 299.004482 -316.316614)
		(width 0.381)
		(layer "F.Cu")
		(net "GND")
	)
	(segment
		(start 52.298346 -223.666558)
		(end 53.403246 -223.666558)
		(width 0.381)
		(layer "F.Cu")
		(net "GND")
	)
	(segment
		(start 189.26175 -13.1572)
		(end 189.226698 -13.122148)
		(width 0.3556)
		(layer "F.Cu")
		(net "GND")
	)
	(segment
		(start 409.748482 -215.166702)
		(end 410.853382 -215.166702)
		(width 0.381)
		(layer "F.Cu")
		(net "GND")
	)
	(segment
		(start 378.37618 -216.250774)
		(end 378.376434 -216.25052)
		(width 0.254)
		(layer "F.Cu")
		(net "GND")
	)
	(segment
		(start 260.180582 -282.316682)
		(end 259.075682 -282.316682)
		(width 0.381)
		(layer "F.Cu")
		(net "GND")
	)
	(segment
		(start 15.774924 -46.999906)
		(end 13.94968 -46.999906)
		(width 0.3556)
		(layer "F.Cu")
		(net "GND")
	)
	(segment
		(start 214.615014 -275.516594)
		(end 215.719914 -275.516594)
		(width 0.381)
		(layer "F.Cu")
		(net "GND")
	)
	(segment
		(start 208.176114 -266.1666)
		(end 209.281014 -266.1666)
		(width 0.381)
		(layer "F.Cu")
		(net "GND")
	)
	(segment
		(start 282.811982 -289.966654)
		(end 283.916882 -289.966654)
		(width 0.381)
		(layer "F.Cu")
		(net "GND")
	)
	(segment
		(start 358.280716 -274.26666)
		(end 358.280462 -274.266914)
		(width 0.254)
		(layer "F.Cu")
		(net "GND")
	)
	(segment
		(start 202.971146 -313.766708)
		(end 204.076046 -313.766708)
		(width 0.381)
		(layer "F.Cu")
		(net "GND")
	)
	(segment
		(start 290.355782 -301.01667)
		(end 291.460682 -301.01667)
		(width 0.381)
		(layer "F.Cu")
		(net "GND")
	)
	(segment
		(start 14.579346 -313.766708)
		(end 15.684246 -313.766708)
		(width 0.381)
		(layer "F.Cu")
		(net "GND")
	)
	(segment
		(start 382.245616 -282.68422)
		(end 382.245616 -283.219906)
		(width 0.254)
		(layer "F.Cu")
		(net "GND")
	)
	(segment
		(start 129.496312 -249.342148)
		(end 129.496312 -248.806208)
		(width 0.2032)
		(layer "F.Cu")
		(net "GND")
	)
	(segment
		(start 120.975374 -360.443272)
		(end 121.984008 -360.443272)
		(width 0.3556)
		(layer "F.Cu")
		(net "GND")
	)
	(segment
		(start 413.192214 -234.716574)
		(end 414.297114 -234.716574)
		(width 0.381)
		(layer "F.Cu")
		(net "GND")
	)
	(segment
		(start 147.73783 -58.638948)
		(end 147.73783 -59.273948)
		(width 0.3556)
		(layer "F.Cu")
		(net "GND")
	)
	(segment
		(start 93.314266 -224.111566)
		(end 93.314266 -223.575626)
		(width 0.2032)
		(layer "F.Cu")
		(net "GND")
	)
	(segment
		(start 361.45978 -231.436418)
		(end 361.460034 -231.436164)
		(width 0.2032)
		(layer "F.Cu")
		(net "GND")
	)
	(segment
		(start 339.484716 -268.84757)
		(end 339.484716 -269.38351)
		(width 0.2032)
		(layer "F.Cu")
		(net "GND")
	)
	(segment
		(start 101.882448 -287.288986)
		(end 101.882194 -287.28924)
		(width 0.254)
		(layer "F.Cu")
		(net "GND")
	)
	(segment
		(start 165.252146 -250.016772)
		(end 166.357046 -250.016772)
		(width 0.381)
		(layer "F.Cu")
		(net "GND")
	)
	(segment
		(start 196.532246 -309.51678)
		(end 195.427346 -309.51678)
		(width 0.381)
		(layer "F.Cu")
		(net "GND")
	)
	(segment
		(start 91.074494 -263.150604)
		(end 91.074494 -263.68629)
		(width 0.2032)
		(layer "F.Cu")
		(net "GND")
	)
	(segment
		(start 458.455014 -301.866808)
		(end 459.559914 -301.866808)
		(width 0.381)
		(layer "F.Cu")
		(net "GND")
	)
	(segment
		(start 136.184894 -272.917158)
		(end 136.654794 -272.639282)
		(width 0.254)
		(layer "F.Cu")
		(net "GND")
	)
	(segment
		(start 171.562014 -278.916638)
		(end 170.457114 -278.916638)
		(width 0.381)
		(layer "F.Cu")
		(net "GND")
	)
	(segment
		(start 60.947046 -278.066754)
		(end 62.051946 -278.066754)
		(width 0.381)
		(layer "F.Cu")
		(net "GND")
	)
	(segment
		(start 18.679414 -277.216616)
		(end 19.784314 -277.216616)
		(width 0.381)
		(layer "F.Cu")
		(net "GND")
	)
	(segment
		(start 369.558316 -284.033468)
		(end 369.558062 -284.033722)
		(width 0.254)
		(layer "F.Cu")
		(net "GND")
	)
	(segment
		(start 46.798992 -99.79152)
		(end 46.750478 -99.840034)
		(width 0.3556)
		(layer "F.Cu")
		(net "GND")
	)
	(segment
		(start 339.748876 -42.811446)
		(end 339.209888 -42.811446)
		(width 0.2032)
		(layer "F.Cu")
		(net "GND")
	)
	(segment
		(start 175.005746 -238.966756)
		(end 173.900846 -238.966756)
		(width 0.381)
		(layer "F.Cu")
		(net "GND")
	)
	(segment
		(start 342.774016 -271.289526)
		(end 342.774016 -271.825212)
		(width 0.2032)
		(layer "F.Cu")
		(net "GND")
	)
	(segment
		(start 212.724746 -290.816792)
		(end 211.619846 -290.816792)
		(width 0.381)
		(layer "F.Cu")
		(net "GND")
	)
	(segment
		(start 197.637146 -304.416714)
		(end 196.532246 -304.416714)
		(width 0.381)
		(layer "F.Cu")
		(net "GND")
	)
	(segment
		(start 123.387866 -250.155964)
		(end 123.387612 -250.15571)
		(width 0.2032)
		(layer "F.Cu")
		(net "GND")
	)
	(segment
		(start 261.285482 -247.466612)
		(end 260.180582 -247.466612)
		(width 0.381)
		(layer "F.Cu")
		(net "GND")
	)
	(segment
		(start 256.080514 -212.616796)
		(end 257.185414 -212.616796)
		(width 0.381)
		(layer "F.Cu")
		(net "GND")
	)
	(segment
		(start 293.497 -344.700352)
		(end 294.437308 -344.700352)
		(width 0.508)
		(layer "F.Cu")
		(net "GND")
	)
	(segment
		(start 338.544916 -283.497782)
		(end 338.544662 -283.498036)
		(width 0.254)
		(layer "F.Cu")
		(net "GND")
	)
	(segment
		(start 53.403246 -234.716574)
		(end 54.724046 -234.716574)
		(width 0.381)
		(layer "F.Cu")
		(net "GND")
	)
	(segment
		(start 107.521248 -285.125414)
		(end 107.521248 -285.6611)
		(width 0.254)
		(layer "F.Cu")
		(net "GND")
	)
	(segment
		(start 125.737112 -241.203226)
		(end 125.737112 -240.667286)
		(width 0.2032)
		(layer "F.Cu")
		(net "GND")
	)
	(segment
		(start 195.427346 -203.266802)
		(end 196.532246 -203.266802)
		(width 0.381)
		(layer "F.Cu")
		(net "GND")
	)
	(segment
		(start 286.255714 -195.616576)
		(end 287.360614 -195.616576)
		(width 0.381)
		(layer "F.Cu")
		(net "GND")
	)
	(segment
		(start 98.482912 -216.78646)
		(end 98.482912 -216.250774)
		(width 0.254)
		(layer "F.Cu")
		(net "GND")
	)
	(segment
		(start 133.835648 -286.7533)
		(end 133.835648 -287.28924)
		(width 0.254)
		(layer "F.Cu")
		(net "GND")
	)
	(segment
		(start 100.362512 -222.76181)
		(end 100.362766 -222.761556)
		(width 0.254)
		(layer "F.Cu")
		(net "GND")
	)
	(segment
		(start 96.243648 -263.96442)
		(end 96.243394 -263.964674)
		(width 0.254)
		(layer "F.Cu")
		(net "GND")
	)
	(segment
		(start 111.640366 -228.180646)
		(end 111.640366 -227.64496)
		(width 0.2032)
		(layer "F.Cu")
		(net "GND")
	)
	(segment
		(start 397.765016 -50.249836)
		(end 395.854428 -50.249836)
		(width 0.254)
		(layer "F.Cu")
		(net "GND")
	)
	(segment
		(start 347.472762 -278.336248)
		(end 347.473016 -278.336502)
		(width 0.2032)
		(layer "F.Cu")
		(net "GND")
	)
	(segment
		(start 93.136466 -100.227384)
		(end 92.501466 -100.227384)
		(width 0.3556)
		(layer "F.Cu")
		(net "GND")
	)
	(segment
		(start 214.291926 -95.153988)
		(end 215.392 -95.153988)
		(width 0.3556)
		(layer "F.Cu")
		(net "GND")
	)
	(segment
		(start 178.000914 -303.566576)
		(end 179.105814 -303.566576)
		(width 0.381)
		(layer "F.Cu")
		(net "GND")
	)
	(segment
		(start 436.928514 -281.466798)
		(end 438.033414 -281.466798)
		(width 0.381)
		(layer "F.Cu")
		(net "GND")
	)
	(segment
		(start 418.397182 -303.566576)
		(end 417.292282 -303.566576)
		(width 0.381)
		(layer "F.Cu")
		(net "GND")
	)
	(segment
		(start 123.857766 -220.041724)
		(end 123.857766 -219.506038)
		(width 0.254)
		(layer "F.Cu")
		(net "GND")
	)
	(segment
		(start 293.799514 -276.366732)
		(end 292.694614 -276.366732)
		(width 0.381)
		(layer "F.Cu")
		(net "GND")
	)
	(segment
		(start 128.556766 -247.714008)
		(end 128.556766 -247.178322)
		(width 0.2032)
		(layer "F.Cu")
		(net "GND")
	)
	(segment
		(start 301.343314 -216.016586)
		(end 302.448214 -216.016586)
		(width 0.381)
		(layer "F.Cu")
		(net "GND")
	)
	(segment
		(start 93.511624 -336.592418)
		(end 93.422978 -336.592418)
		(width 0.254)
		(layer "F.Cu")
		(net "GND")
	)
	(segment
		(start 107.990894 -268.033754)
		(end 107.991148 -268.034008)
		(width 0.254)
		(layer "F.Cu")
		(net "GND")
	)
	(segment
		(start 101.302312 -216.250774)
		(end 101.302566 -216.25052)
		(width 0.254)
		(layer "F.Cu")
		(net "GND")
	)
	(segment
		(start 137.022586 -248.798588)
		(end 137.014966 -248.806208)
		(width 0.254)
		(layer "F.Cu")
		(net "GND")
	)
	(segment
		(start 266.619482 -213.46668)
		(end 267.724382 -213.46668)
		(width 0.381)
		(layer "F.Cu")
		(net "GND")
	)
	(segment
		(start 136.655048 -272.103342)
		(end 136.19988 -271.834102)
		(width 0.254)
		(layer "F.Cu")
		(net "GND")
	)
	(segment
		(start 104.13492 -354.045012)
		(end 104.76611 -354.045012)
		(width 0.381)
		(layer "F.Cu")
		(net "GND")
	)
	(segment
		(start 86.375494 -261.522718)
		(end 87.315294 -262.058658)
		(width 0.254)
		(layer "F.Cu")
		(net "GND")
	)
	(segment
		(start 342.198452 -335.541112)
		(end 341.839804 -335.89976)
		(width 0.2032)
		(layer "F.Cu")
		(net "GND")
	)
	(segment
		(start 213.621112 -19.517614)
		(end 215.73617 -19.517614)
		(width 0.3556)
		(layer "F.Cu")
		(net "GND")
	)
	(segment
		(start 42.415714 -238.116618)
		(end 41.310814 -238.116618)
		(width 0.381)
		(layer "F.Cu")
		(net "GND")
	)
	(segment
		(start 363.919516 -272.103342)
		(end 363.919262 -272.639282)
		(width 0.2032)
		(layer "F.Cu")
		(net "GND")
	)
	(segment
		(start 396.20444 -60.960508)
		(end 396.493746 -61.249814)
		(width 0.254)
		(layer "F.Cu")
		(net "GND")
	)
	(segment
		(start 316.996572 -60.315348)
		(end 316.380622 -60.315348)
		(width 0.381)
		(layer "F.Cu")
		(net "GND")
	)
	(segment
		(start 167.461946 -279.766776)
		(end 166.357046 -279.766776)
		(width 0.381)
		(layer "F.Cu")
		(net "GND")
	)
	(segment
		(start 137.594594 -268.84757)
		(end 136.654794 -269.38351)
		(width 0.254)
		(layer "F.Cu")
		(net "GND")
	)
	(segment
		(start 87.205312 -228.1809)
		(end 87.205312 -227.64496)
		(width 0.254)
		(layer "F.Cu")
		(net "GND")
	)
	(segment
		(start 57.503314 -205.816708)
		(end 58.608214 -205.816708)
		(width 0.381)
		(layer "F.Cu")
		(net "GND")
	)
	(segment
		(start 305.443382 -275.516594)
		(end 306.548282 -275.516594)
		(width 0.381)
		(layer "F.Cu")
		(net "GND")
	)
	(segment
		(start 375.666762 -260.430518)
		(end 375.667016 -260.430772)
		(width 0.254)
		(layer "F.Cu")
		(net "GND")
	)
	(segment
		(start 282.811982 -244.066568)
		(end 283.916882 -244.066568)
		(width 0.381)
		(layer "F.Cu")
		(net "GND")
	)
	(segment
		(start 382.168908 -78.824074)
		(end 382.168908 -79.468218)
		(width 0.381)
		(layer "F.Cu")
		(net "GND")
	)
	(segment
		(start 126.646178 -339.26526)
		(end 126.47295 -339.683344)
		(width 0.1778)
		(layer "F.Cu")
		(net "GND")
	)
	(segment
		(start 254.975614 -203.266802)
		(end 256.080514 -203.266802)
		(width 0.381)
		(layer "F.Cu")
		(net "GND")
	)
	(segment
		(start 422.82364 -51.00828)
		(end 420.873428 -52.958492)
		(width 0.3556)
		(layer "F.Cu")
		(net "GND")
	)
	(segment
		(start 6.599174 -98.496882)
		(end 6.579362 -98.516694)
		(width 0.3556)
		(layer "F.Cu")
		(net "GND")
	)
	(segment
		(start 261.285482 -213.46668)
		(end 260.180582 -213.46668)
		(width 0.381)
		(layer "F.Cu")
		(net "GND")
	)
	(segment
		(start 98.592894 -289.195002)
		(end 98.592894 -289.807142)
		(width 0.2032)
		(layer "F.Cu")
		(net "GND")
	)
	(segment
		(start 424.836082 -221.116652)
		(end 425.940982 -221.116652)
		(width 0.381)
		(layer "F.Cu")
		(net "GND")
	)
	(segment
		(start 328.194162 -53.902102)
		(end 328.244962 -53.952902)
		(width 0.2032)
		(layer "F.Cu")
		(net "GND")
	)
	(segment
		(start 300.238414 -283.166566)
		(end 301.343314 -283.166566)
		(width 0.381)
		(layer "F.Cu")
		(net "GND")
	)
	(segment
		(start 114.73688 -104.479598)
		(end 115.75288 -104.479598)
		(width 0.3556)
		(layer "F.Cu")
		(net "GND")
	)
	(segment
		(start 27.547062 -8.320024)
		(end 27.547062 -9.424924)
		(width 0.3556)
		(layer "F.Cu")
		(net "GND")
	)
	(segment
		(start 132.315712 -226.017582)
		(end 132.315966 -226.017328)
		(width 0.254)
		(layer "F.Cu")
		(net "GND")
	)
	(segment
		(start 337.02498 -224.389696)
		(end 337.025234 -224.389442)
		(width 0.254)
		(layer "F.Cu")
		(net "GND")
	)
	(segment
		(start 169.113962 -207.51673)
		(end 170.457114 -207.51673)
		(width 0.381)
		(layer "F.Cu")
		(net "GND")
	)
	(segment
		(start 395.62024 -50.015648)
		(end 395.885924 -49.749964)
		(width 0.254)
		(layer "F.Cu")
		(net "GND")
	)
	(segment
		(start 433.484782 -205.816708)
		(end 434.589682 -205.816708)
		(width 0.381)
		(layer "F.Cu")
		(net "GND")
	)
	(segment
		(start 157.708346 -201.56678)
		(end 158.813246 -201.56678)
		(width 0.381)
		(layer "F.Cu")
		(net "GND")
	)
	(segment
		(start 99.339654 -96.758506)
		(end 99.35464 -96.773492)
		(width 0.3556)
		(layer "F.Cu")
		(net "GND")
	)
	(segment
		(start 160.142174 -217.716608)
		(end 158.813246 -217.716608)
		(width 0.381)
		(layer "F.Cu")
		(net "GND")
	)
	(segment
		(start 162.913314 -289.966654)
		(end 164.018214 -289.966654)
		(width 0.381)
		(layer "F.Cu")
		(net "GND")
	)
	(segment
		(start 349.97644 -333.790544)
		(end 349.97644 -333.330804)
		(width 0.2032)
		(layer "F.Cu")
		(net "GND")
	)
	(segment
		(start 343.822274 -54.558692)
		(end 343.819734 -54.558692)
		(width 0.2032)
		(layer "F.Cu")
		(net "GND")
	)
	(segment
		(start 101.835204 -356.160578)
		(end 101.27488 -356.160578)
		(width 0.381)
		(layer "F.Cu")
		(net "GND")
	)
	(segment
		(start 14.579346 -300.166786)
		(end 15.684246 -300.166786)
		(width 0.381)
		(layer "F.Cu")
		(net "GND")
	)
	(segment
		(start 123.387612 -235.505752)
		(end 123.387612 -234.970066)
		(width 0.2032)
		(layer "F.Cu")
		(net "GND")
	)
	(segment
		(start 33.767014 -224.516696)
		(end 34.871914 -224.516696)
		(width 0.381)
		(layer "F.Cu")
		(net "GND")
	)
	(segment
		(start 457.221082 -261.066788)
		(end 456.116182 -261.066788)
		(width 0.381)
		(layer "F.Cu")
		(net "GND")
	)
	(segment
		(start 171.562014 -226.216718)
		(end 170.457114 -226.216718)
		(width 0.381)
		(layer "F.Cu")
		(net "GND")
	)
	(segment
		(start 366.268762 -281.05608)
		(end 366.268762 -281.59202)
		(width 0.254)
		(layer "F.Cu")
		(net "GND")
	)
	(segment
		(start 326.584818 -38.2905)
		(end 326.584818 -38.945566)
		(width 0.2032)
		(layer "F.Cu")
		(net "GND")
	)
	(segment
		(start 193.088514 -264.466578)
		(end 191.983614 -264.466578)
		(width 0.381)
		(layer "F.Cu")
		(net "GND")
	)
	(segment
		(start 339.84438 -233.064304)
		(end 339.84438 -232.528364)
		(width 0.2032)
		(layer "F.Cu")
		(net "GND")
	)
	(segment
		(start 447.16192 -8.320024)
		(end 447.16192 -7.20471)
		(width 0.3556)
		(layer "F.Cu")
		(net "GND")
	)
	(segment
		(start 374.257316 -286.7533)
		(end 374.257316 -287.288986)
		(width 0.254)
		(layer "F.Cu")
		(net "GND")
	)
	(segment
		(start 337.02498 -220.041978)
		(end 337.025234 -220.041724)
		(width 0.254)
		(layer "F.Cu")
		(net "GND")
	)
	(segment
		(start 122.448066 -233.87812)
		(end 122.447812 -233.877866)
		(width 0.254)
		(layer "F.Cu")
		(net "GND")
	)
	(segment
		(start 115.039648 -279.150064)
		(end 115.039394 -279.150318)
		(width 0.254)
		(layer "F.Cu")
		(net "GND")
	)
	(segment
		(start 117.749066 -223.575626)
		(end 117.749066 -224.111566)
		(width 0.2032)
		(layer "F.Cu")
		(net "GND")
	)
	(segment
		(start 58.608214 -224.516696)
		(end 57.503314 -224.516696)
		(width 0.381)
		(layer "F.Cu")
		(net "GND")
	)
	(segment
		(start 204.076046 -258.516628)
		(end 205.180946 -258.516628)
		(width 0.381)
		(layer "F.Cu")
		(net "GND")
	)
	(segment
		(start 300.238414 -270.416782)
		(end 301.343314 -270.416782)
		(width 0.381)
		(layer "F.Cu")
		(net "GND")
	)
	(segment
		(start 104.701848 -268.84757)
		(end 104.701594 -268.847824)
		(width 0.254)
		(layer "F.Cu")
		(net "GND")
	)
	(segment
		(start 281.707082 -301.01667)
		(end 282.811982 -301.01667)
		(width 0.381)
		(layer "F.Cu")
		(net "GND")
	)
	(segment
		(start 125.847094 -263.150604)
		(end 125.847094 -263.68629)
		(width 0.2032)
		(layer "F.Cu")
		(net "GND")
	)
	(segment
		(start 429.129952 -390.855962)
		(end 429.764952 -390.855962)
		(width 0.3556)
		(layer "F.Cu")
		(net "GND")
	)
	(segment
		(start 170.457114 -221.116652)
		(end 171.562014 -221.116652)
		(width 0.381)
		(layer "F.Cu")
		(net "GND")
	)
	(segment
		(start 439.923682 -210.066636)
		(end 441.028582 -210.066636)
		(width 0.381)
		(layer "F.Cu")
		(net "GND")
	)
	(segment
		(start 346.063316 -278.614378)
		(end 346.063316 -279.150318)
		(width 0.254)
		(layer "F.Cu")
		(net "GND")
	)
	(segment
		(start 202.971146 -267.016738)
		(end 204.076046 -267.016738)
		(width 0.381)
		(layer "F.Cu")
		(net "GND")
	)
	(segment
		(start 376.606562 -255.547368)
		(end 376.606816 -255.547622)
		(width 0.2032)
		(layer "F.Cu")
		(net "GND")
	)
	(segment
		(start 254.975614 -244.916706)
		(end 256.080514 -244.916706)
		(width 0.381)
		(layer "F.Cu")
		(net "GND")
	)
	(segment
		(start 307.566314 -220.342968)
		(end 307.642514 -220.266768)
		(width 0.381)
		(layer "F.Cu")
		(net "GND")
	)
	(segment
		(start 88.725248 -262.336534)
		(end 88.725248 -262.87222)
		(width 0.2032)
		(layer "F.Cu")
		(net "GND")
	)
	(segment
		(start 419.76802 -235.566712)
		(end 418.397182 -235.566712)
		(width 0.381)
		(layer "F.Cu")
		(net "GND")
	)
	(segment
		(start 193.088514 -275.516594)
		(end 194.193414 -275.516594)
		(width 0.381)
		(layer "F.Cu")
		(net "GND")
	)
	(segment
		(start 218.52763 -131.973828)
		(end 218.52763 -132.629148)
		(width 0.3556)
		(layer "F.Cu")
		(net "GND")
	)
	(segment
		(start 158.813246 -204.96657)
		(end 157.386528 -204.96657)
		(width 0.381)
		(layer "F.Cu")
		(net "GND")
	)
	(segment
		(start 342.190578 -43.281346)
		(end 342.19134 -43.281346)
		(width 0.254)
		(layer "F.Cu")
		(net "GND")
	)
	(segment
		(start 59.626246 -220.342968)
		(end 59.702446 -220.266768)
		(width 0.381)
		(layer "F.Cu")
		(net "GND")
	)
	(segment
		(start 194.193414 -247.466612)
		(end 193.088514 -247.466612)
		(width 0.381)
		(layer "F.Cu")
		(net "GND")
	)
	(segment
		(start 378.846334 -246.900446)
		(end 378.84608 -246.900192)
		(width 0.2032)
		(layer "F.Cu")
		(net "GND")
	)
	(segment
		(start 307.782214 -222.04299)
		(end 307.858414 -221.96679)
		(width 0.381)
		(layer "F.Cu")
		(net "GND")
	)
	(segment
		(start 453.121014 -295.06672)
		(end 452.016114 -295.06672)
		(width 0.381)
		(layer "F.Cu")
		(net "GND")
	)
	(segment
		(start 309.123588 -36.806886)
		(end 309.123588 -37.822886)
		(width 0.3556)
		(layer "F.Cu")
		(net "GND")
	)
	(segment
		(start 91.544648 -256.361184)
		(end 91.544394 -256.361438)
		(width 0.2032)
		(layer "F.Cu")
		(net "GND")
	)
	(segment
		(start 296.794682 -241.516662)
		(end 297.899582 -241.516662)
		(width 0.381)
		(layer "F.Cu")
		(net "GND")
	)
	(segment
		(start 312.987182 -210.066636)
		(end 314.307982 -210.066636)
		(width 0.381)
		(layer "F.Cu")
		(net "GND")
	)
	(segment
		(start 449.677282 -249.166634)
		(end 448.572382 -249.166634)
		(width 0.381)
		(layer "F.Cu")
		(net "GND")
	)
	(segment
		(start 370.38788 -238.76127)
		(end 370.38788 -238.225584)
		(width 0.2032)
		(layer "F.Cu")
		(net "GND")
	)
	(segment
		(start 453.121014 -229.616762)
		(end 452.016114 -229.616762)
		(width 0.381)
		(layer "F.Cu")
		(net "GND")
	)
	(segment
		(start 414.297114 -223.666558)
		(end 415.402014 -223.666558)
		(width 0.381)
		(layer "F.Cu")
		(net "GND")
	)
	(segment
		(start 9.277096 -100.417884)
		(end 9.277096 -101.095302)
		(width 0.3556)
		(layer "F.Cu")
		(net "GND")
	)
	(segment
		(start 425.96689 -8.320024)
		(end 425.96689 -9.424924)
		(width 0.3556)
		(layer "F.Cu")
		(net "GND")
	)
	(segment
		(start 409.748482 -232.166668)
		(end 410.853382 -232.166668)
		(width 0.381)
		(layer "F.Cu")
		(net "GND")
	)
	(segment
		(start 365.890302 -389.838184)
		(end 365.441484 -389.838184)
		(width 0.3556)
		(layer "F.Cu")
		(net "GND")
	)
	(segment
		(start 256.080514 -221.96679)
		(end 257.185414 -221.96679)
		(width 0.381)
		(layer "F.Cu")
		(net "GND")
	)
	(segment
		(start 286.260032 -393.77239)
		(end 286.260032 -390.459976)
		(width 0.4572)
		(layer "F.Cu")
		(net "GND")
	)
	(segment
		(start 38.315646 -306.116736)
		(end 37.210746 -306.116736)
		(width 0.381)
		(layer "F.Cu")
		(net "GND")
	)
	(segment
		(start 184.439814 -267.866622)
		(end 185.544714 -267.866622)
		(width 0.381)
		(layer "F.Cu")
		(net "GND")
	)
	(segment
		(start 278.711914 -201.56678)
		(end 279.816814 -201.56678)
		(width 0.381)
		(layer "F.Cu")
		(net "GND")
	)
	(segment
		(start 411.958282 -303.566576)
		(end 410.853382 -303.566576)
		(width 0.381)
		(layer "F.Cu")
		(net "GND")
	)
	(segment
		(start 125.377448 -257.45313)
		(end 125.377448 -257.98907)
		(width 0.2032)
		(layer "F.Cu")
		(net "GND")
	)
	(segment
		(start 170.457114 -261.066788)
		(end 171.562014 -261.066788)
		(width 0.381)
		(layer "F.Cu")
		(net "GND")
	)
	(segment
		(start 361.573826 -365.690404)
		(end 361.652566 -365.769144)
		(width 0.381)
		(layer "F.Cu")
		(net "GND")
	)
	(segment
		(start 34.871914 -305.266598)
		(end 33.767014 -305.266598)
		(width 0.381)
		(layer "F.Cu")
		(net "GND")
	)
	(segment
		(start 90.964512 -249.342148)
		(end 90.964766 -249.341894)
		(width 0.2032)
		(layer "F.Cu")
		(net "GND")
	)
	(segment
		(start 48.638714 -312.91657)
		(end 49.959514 -312.91657)
		(width 0.381)
		(layer "F.Cu")
		(net "GND")
	)
	(segment
		(start 199.527414 -202.416664)
		(end 200.632314 -202.416664)
		(width 0.381)
		(layer "F.Cu")
		(net "GND")
	)
	(segment
		(start 398.533874 -185.686954)
		(end 398.533874 -185.96991)
		(width 0.3556)
		(layer "F.Cu")
		(net "GND")
	)
	(segment
		(start 463.659982 -219.41663)
		(end 464.764882 -219.41663)
		(width 0.381)
		(layer "F.Cu")
		(net "GND")
	)
	(segment
		(start 197.637146 -278.066754)
		(end 196.532246 -278.066754)
		(width 0.381)
		(layer "F.Cu")
		(net "GND")
	)
	(segment
		(start 345.554554 -45.949108)
		(end 345.15171 -45.350176)
		(width 0.1778)
		(layer "F.Cu")
		(net "GND")
	)
	(segment
		(start 452.016114 -229.616762)
		(end 450.911214 -229.616762)
		(width 0.381)
		(layer "F.Cu")
		(net "GND")
	)
	(segment
		(start 347.36278 -222.76181)
		(end 347.363034 -222.761556)
		(width 0.254)
		(layer "F.Cu")
		(net "GND")
	)
	(segment
		(start 89.664794 -268.84757)
		(end 89.664794 -269.38351)
		(width 0.2032)
		(layer "F.Cu")
		(net "GND")
	)
	(segment
		(start 7.035546 -238.966756)
		(end 8.140446 -238.966756)
		(width 0.381)
		(layer "F.Cu")
		(net "GND")
	)
	(segment
		(start 18.679414 -262.76681)
		(end 19.784314 -262.76681)
		(width 0.381)
		(layer "F.Cu")
		(net "GND")
	)
	(segment
		(start 429.384714 -236.416596)
		(end 430.489614 -236.416596)
		(width 0.381)
		(layer "F.Cu")
		(net "GND")
	)
	(segment
		(start 92.014294 -255.011682)
		(end 92.014294 -255.547622)
		(width 0.2032)
		(layer "F.Cu")
		(net "GND")
	)
	(segment
		(start 38.315646 -212.616796)
		(end 37.210746 -212.616796)
		(width 0.381)
		(layer "F.Cu")
		(net "GND")
	)
	(segment
		(start 428.279814 -231.316784)
		(end 429.384714 -231.316784)
		(width 0.381)
		(layer "F.Cu")
		(net "GND")
	)
	(segment
		(start 423.36974 -382.361948)
		(end 423.804842 -382.361948)
		(width 0.3556)
		(layer "F.Cu")
		(net "GND")
	)
	(segment
		(start 85.379052 -103.259636)
		(end 84.726272 -103.259636)
		(width 0.3556)
		(layer "F.Cu")
		(net "GND")
	)
	(segment
		(start 211.619846 -258.516628)
		(end 212.724746 -258.516628)
		(width 0.381)
		(layer "F.Cu")
		(net "GND")
	)
	(segment
		(start 11.135614 -288.266632)
		(end 12.240514 -288.266632)
		(width 0.381)
		(layer "F.Cu")
		(net "GND")
	)
	(segment
		(start 20.889214 -204.116686)
		(end 19.784314 -204.116686)
		(width 0.381)
		(layer "F.Cu")
		(net "GND")
	)
	(segment
		(start 300.238414 -306.116736)
		(end 301.343314 -306.116736)
		(width 0.381)
		(layer "F.Cu")
		(net "GND")
	)
	(segment
		(start 154.27198 -68.290948)
		(end 153.60015 -68.962778)
		(width 0.3556)
		(layer "F.Cu")
		(net "GND")
	)
	(segment
		(start 94.364048 -260.708902)
		(end 94.364048 -261.244588)
		(width 0.2032)
		(layer "F.Cu")
		(net "GND")
	)
	(segment
		(start 346.384626 -38.465252)
		(end 346.559378 -38.2905)
		(width 0.2032)
		(layer "F.Cu")
		(net "GND")
	)
	(segment
		(start 339.484716 -273.730974)
		(end 339.484716 -274.266914)
		(width 0.2032)
		(layer "F.Cu")
		(net "GND")
	)
	(segment
		(start 410.853382 -196.466714)
		(end 411.958282 -196.466714)
		(width 0.381)
		(layer "F.Cu")
		(net "GND")
	)
	(segment
		(start 371.437916 -262.87222)
		(end 371.437662 -262.872474)
		(width 0.254)
		(layer "F.Cu")
		(net "GND")
	)
	(segment
		(start 212.724746 -306.116736)
		(end 211.619846 -306.116736)
		(width 0.381)
		(layer "F.Cu")
		(net "GND")
	)
	(segment
		(start 129.496312 -222.76181)
		(end 129.496566 -222.761556)
		(width 0.254)
		(layer "F.Cu")
		(net "GND")
	)
	(segment
		(start 65.047114 -316.316614)
		(end 66.152014 -316.316614)
		(width 0.381)
		(layer "F.Cu")
		(net "GND")
	)
	(segment
		(start 24.447754 -399.932144)
		(end 24.447754 -400.693128)
		(width 0.4572)
		(layer "F.Cu")
		(net "GND")
	)
	(segment
		(start 100.942648 -263.96442)
		(end 100.942648 -264.500106)
		(width 0.254)
		(layer "F.Cu")
		(net "GND")
	)
	(segment
		(start 191.983614 -272.966688)
		(end 193.088514 -272.966688)
		(width 0.381)
		(layer "F.Cu")
		(net "GND")
	)
	(segment
		(start 294.691562 -423.954448)
		(end 295.049702 -423.954448)
		(width 0.3556)
		(layer "F.Cu")
		(net "GND")
	)
	(segment
		(start 19.784314 -211.766658)
		(end 18.679414 -211.766658)
		(width 0.381)
		(layer "F.Cu")
		(net "GND")
	)
	(segment
		(start 42.415714 -241.516662)
		(end 41.310814 -241.516662)
		(width 0.381)
		(layer "F.Cu")
		(net "GND")
	)
	(segment
		(start 240.522252 -251.221748)
		(end 240.522252 -251.755148)
		(width 0.3556)
		(layer "F.Cu")
		(net "GND")
	)
	(segment
		(start 441.028582 -262.76681)
		(end 442.133482 -262.76681)
		(width 0.381)
		(layer "F.Cu")
		(net "GND")
	)
	(segment
		(start 88.615012 -230.622348)
		(end 88.615012 -230.086662)
		(width 0.2032)
		(layer "F.Cu")
		(net "GND")
	)
	(segment
		(start 162.913314 -235.566712)
		(end 162.938206 -235.591604)
		(width 0.381)
		(layer "F.Cu")
		(net "GND")
	)
	(segment
		(start 33.767014 -210.066636)
		(end 34.871914 -210.066636)
		(width 0.381)
		(layer "F.Cu")
		(net "GND")
	)
	(segment
		(start 420.736014 -317.166752)
		(end 421.840914 -317.166752)
		(width 0.381)
		(layer "F.Cu")
		(net "GND")
	)
	(segment
		(start 439.923682 -238.116618)
		(end 441.028582 -238.116618)
		(width 0.381)
		(layer "F.Cu")
		(net "GND")
	)
	(segment
		(start 407.858214 -317.166752)
		(end 406.753314 -317.166752)
		(width 0.381)
		(layer "F.Cu")
		(net "GND")
	)
	(segment
		(start 181.444646 -197.316598)
		(end 182.549546 -197.316598)
		(width 0.381)
		(layer "F.Cu")
		(net "GND")
	)
	(segment
		(start 262.519414 -276.366732)
		(end 263.624314 -276.366732)
		(width 0.381)
		(layer "F.Cu")
		(net "GND")
	)
	(segment
		(start 121.618248 -273.730974)
		(end 121.618248 -274.266914)
		(width 0.2032)
		(layer "F.Cu")
		(net "GND")
	)
	(segment
		(start 188.839348 -423.46118)
		(end 188.839348 -423.209212)
		(width 0.3556)
		(layer "F.Cu")
		(net "GND")
	)
	(segment
		(start 290.355782 -239.81664)
		(end 291.460682 -239.81664)
		(width 0.381)
		(layer "F.Cu")
		(net "GND")
	)
	(segment
		(start 428.279814 -273.816572)
		(end 429.384714 -273.816572)
		(width 0.381)
		(layer "F.Cu")
		(net "GND")
	)
	(segment
		(start 115.399566 -229.808532)
		(end 115.399566 -229.272846)
		(width 0.2032)
		(layer "F.Cu")
		(net "GND")
	)
	(segment
		(start 453.121014 -238.966756)
		(end 452.016114 -238.966756)
		(width 0.381)
		(layer "F.Cu")
		(net "GND")
	)
	(segment
		(start 54.508146 -301.866808)
		(end 53.403246 -301.866808)
		(width 0.381)
		(layer "F.Cu")
		(net "GND")
	)
	(segment
		(start 338.120736 -53.149246)
		(end 337.581748 -53.149246)
		(width 0.2032)
		(layer "F.Cu")
		(net "GND")
	)
	(segment
		(start 187.883546 -285.716726)
		(end 188.988446 -285.716726)
		(width 0.381)
		(layer "F.Cu")
		(net "GND")
	)
	(segment
		(start 261.285482 -286.56661)
		(end 260.180582 -286.56661)
		(width 0.381)
		(layer "F.Cu")
		(net "GND")
	)
	(segment
		(start 436.928514 -267.016738)
		(end 438.033414 -267.016738)
		(width 0.381)
		(layer "F.Cu")
		(net "GND")
	)
	(segment
		(start 131.375912 -216.78646)
		(end 131.375912 -216.250774)
		(width 0.254)
		(layer "F.Cu")
		(net "GND")
	)
	(segment
		(start 118.804944 -78.698852)
		(end 118.804944 -79.486252)
		(width 0.254)
		(layer "F.Cu")
		(net "GND")
	)
	(segment
		(start 138.424666 -225.739198)
		(end 138.424666 -225.203258)
		(width 0.254)
		(layer "F.Cu")
		(net "GND")
	)
	(segment
		(start 185.544714 -271.266666)
		(end 186.649614 -271.266666)
		(width 0.381)
		(layer "F.Cu")
		(net "GND")
	)
	(segment
		(start 134.678674 -342.964008)
		(end 134.678674 -342.5317)
		(width 0.2032)
		(layer "F.Cu")
		(net "GND")
	)
	(segment
		(start 63.43269 -39.381176)
		(end 63.43269 -38.784276)
		(width 0.3556)
		(layer "F.Cu")
		(net "GND")
	)
	(segment
		(start 452.016114 -301.866808)
		(end 450.911214 -301.866808)
		(width 0.381)
		(layer "F.Cu")
		(net "GND")
	)
	(segment
		(start 300.238414 -221.96679)
		(end 301.343314 -221.96679)
		(width 0.381)
		(layer "F.Cu")
		(net "GND")
	)
	(segment
		(start 200.632314 -222.816674)
		(end 201.737214 -222.816674)
		(width 0.381)
		(layer "F.Cu")
		(net "GND")
	)
	(segment
		(start 456.116182 -249.166634)
		(end 455.011282 -249.166634)
		(width 0.381)
		(layer "F.Cu")
		(net "GND")
	)
	(segment
		(start 110.340648 -270.475456)
		(end 110.340648 -271.011142)
		(width 0.254)
		(layer "F.Cu")
		(net "GND")
	)
	(segment
		(start 429.384714 -234.716574)
		(end 430.489614 -234.716574)
		(width 0.381)
		(layer "F.Cu")
		(net "GND")
	)
	(segment
		(start 49.959514 -262.76681)
		(end 51.064414 -262.76681)
		(width 0.381)
		(layer "F.Cu")
		(net "GND")
	)
	(segment
		(start 458.455014 -307.816758)
		(end 459.559914 -307.816758)
		(width 0.381)
		(layer "F.Cu")
		(net "GND")
	)
	(segment
		(start 181.308756 -358.534716)
		(end 181.14518 -358.698292)
		(width 0.381)
		(layer "F.Cu")
		(net "GND")
	)
	(segment
		(start 157.505146 -283.166566)
		(end 158.813246 -283.166566)
		(width 0.381)
		(layer "F.Cu")
		(net "GND")
	)
	(segment
		(start 419.502082 -215.166702)
		(end 418.397182 -215.166702)
		(width 0.381)
		(layer "F.Cu")
		(net "GND")
	)
	(segment
		(start 305.443382 -198.166736)
		(end 306.548282 -198.166736)
		(width 0.381)
		(layer "F.Cu")
		(net "GND")
	)
	(segment
		(start 45.859446 -309.51678)
		(end 46.964346 -309.51678)
		(width 0.381)
		(layer "F.Cu")
		(net "GND")
	)
	(segment
		(start 122.558048 -260.708902)
		(end 122.558048 -261.244588)
		(width 0.2032)
		(layer "F.Cu")
		(net "GND")
	)
	(segment
		(start 190.093346 -217.716608)
		(end 188.988446 -217.716608)
		(width 0.381)
		(layer "F.Cu")
		(net "GND")
	)
	(segment
		(start 134.305548 -282.68422)
		(end 134.305548 -283.219906)
		(width 0.254)
		(layer "F.Cu")
		(net "GND")
	)
	(segment
		(start 373.207534 -214.344758)
		(end 373.207534 -213.732618)
		(width 0.254)
		(layer "F.Cu")
		(net "GND")
	)
	(segment
		(start 91.074494 -273.452844)
		(end 91.074748 -273.453098)
		(width 0.2032)
		(layer "F.Cu")
		(net "GND")
	)
	(segment
		(start 314.710572 -55.235348)
		(end 314.092336 -55.235348)
		(width 0.3556)
		(layer "F.Cu")
		(net "GND")
	)
	(segment
		(start 267.724382 -272.966688)
		(end 268.829282 -272.966688)
		(width 0.381)
		(layer "F.Cu")
		(net "GND")
	)
	(segment
		(start 365.219234 -229.808532)
		(end 365.219234 -229.272846)
		(width 0.2032)
		(layer "F.Cu")
		(net "GND")
	)
	(segment
		(start 129.026412 -228.994716)
		(end 129.026412 -228.45903)
		(width 0.2032)
		(layer "F.Cu")
		(net "GND")
	)
	(segment
		(start 88.615266 -240.389156)
		(end 88.615012 -240.388902)
		(width 0.2032)
		(layer "F.Cu")
		(net "GND")
	)
	(segment
		(start 162.913314 -305.266598)
		(end 164.018214 -305.266598)
		(width 0.381)
		(layer "F.Cu")
		(net "GND")
	)
	(segment
		(start 378.84608 -230.622348)
		(end 378.84608 -230.086662)
		(width 0.2032)
		(layer "F.Cu")
		(net "GND")
	)
	(segment
		(start 348.412562 -279.96388)
		(end 348.412816 -279.964134)
		(width 0.254)
		(layer "F.Cu")
		(net "GND")
	)
	(segment
		(start 360.990134 -215.436958)
		(end 360.98988 -215.436704)
		(width 0.2032)
		(layer "F.Cu")
		(net "GND")
	)
	(segment
		(start 453.121014 -317.166752)
		(end 452.016114 -317.166752)
		(width 0.381)
		(layer "F.Cu")
		(net "GND")
	)
	(segment
		(start 196.532246 -268.71676)
		(end 197.637146 -268.71676)
		(width 0.381)
		(layer "F.Cu")
		(net "GND")
	)
	(segment
		(start 214.615014 -286.56661)
		(end 215.719914 -286.56661)
		(width 0.381)
		(layer "F.Cu")
		(net "GND")
	)
	(segment
		(start 163.843462 -17.630394)
		(end 163.8681 -17.655032)
		(width 0.3556)
		(layer "F.Cu")
		(net "GND")
	)
	(segment
		(start 297.899582 -284.866588)
		(end 299.004482 -284.866588)
		(width 0.381)
		(layer "F.Cu")
		(net "GND")
	)
	(segment
		(start 95.663512 -247.714262)
		(end 95.663512 -247.178576)
		(width 0.2032)
		(layer "F.Cu")
		(net "GND")
	)
	(segment
		(start 453.121014 -261.916672)
		(end 452.016114 -261.916672)
		(width 0.381)
		(layer "F.Cu")
		(net "GND")
	)
	(segment
		(start 199.527414 -295.916604)
		(end 200.632314 -295.916604)
		(width 0.381)
		(layer "F.Cu")
		(net "GND")
	)
	(segment
		(start 337.495134 -246.900446)
		(end 337.49488 -246.900192)
		(width 0.2032)
		(layer "F.Cu")
		(net "GND")
	)
	(segment
		(start 311.882282 -267.866622)
		(end 312.987182 -267.866622)
		(width 0.381)
		(layer "F.Cu")
		(net "GND")
	)
	(segment
		(start 409.748482 -266.1666)
		(end 410.853382 -266.1666)
		(width 0.381)
		(layer "F.Cu")
		(net "GND")
	)
	(segment
		(start 343.819734 -48.919892)
		(end 343.81948 -48.920146)
		(width 0.254)
		(layer "F.Cu")
		(net "GND")
	)
	(segment
		(start 277.607014 -296.766742)
		(end 278.711914 -296.766742)
		(width 0.381)
		(layer "F.Cu")
		(net "GND")
	)
	(segment
		(start 361.569762 -261.522718)
		(end 361.569762 -262.058658)
		(width 0.254)
		(layer "F.Cu")
		(net "GND")
	)
	(segment
		(start 380.835916 -259.093462)
		(end 380.835662 -259.616956)
		(width 0.2032)
		(layer "F.Cu")
		(net "GND")
	)
	(segment
		(start 358.280716 -254.197612)
		(end 358.280716 -254.733298)
		(width 0.254)
		(layer "F.Cu")
		(net "GND")
	)
	(segment
		(start 91.904312 -223.297496)
		(end 91.904312 -222.76181)
		(width 0.254)
		(layer "F.Cu")
		(net "GND")
	)
	(segment
		(start 296.578782 -312.91657)
		(end 297.899582 -312.91657)
		(width 0.381)
		(layer "F.Cu")
		(net "GND")
	)
	(segment
		(start 129.496312 -234.69219)
		(end 129.496312 -234.15625)
		(width 0.2032)
		(layer "F.Cu")
		(net "GND")
	)
	(segment
		(start 429.384714 -203.266802)
		(end 430.489614 -203.266802)
		(width 0.381)
		(layer "F.Cu")
		(net "GND")
	)
	(segment
		(start 428.279814 -290.816792)
		(end 429.384714 -290.816792)
		(width 0.381)
		(layer "F.Cu")
		(net "GND")
	)
	(segment
		(start 217.062558 -27.76347)
		(end 216.810844 -28.015184)
		(width 0.3556)
		(layer "F.Cu")
		(net "GND")
	)
	(segment
		(start 263.624314 -214.316564)
		(end 264.729214 -214.316564)
		(width 0.381)
		(layer "F.Cu")
		(net "GND")
	)
	(segment
		(start 113.812066 -396.157958)
		(end 113.812066 -396.792958)
		(width 0.3556)
		(layer "F.Cu")
		(net "GND")
	)
	(segment
		(start 297.906948 -367.919508)
		(end 297.583098 -367.919508)
		(width 0.381)
		(layer "F.Cu")
		(net "GND")
	)
	(segment
		(start 293.799514 -233.016806)
		(end 294.904414 -233.016806)
		(width 0.381)
		(layer "F.Cu")
		(net "GND")
	)
	(segment
		(start 413.395414 -287.416748)
		(end 414.297114 -287.416748)
		(width 0.381)
		(layer "F.Cu")
		(net "GND")
	)
	(segment
		(start 137.594594 -255.825498)
		(end 137.124948 -255.547368)
		(width 0.254)
		(layer "F.Cu")
		(net "GND")
	)
	(segment
		(start 104.121712 -216.250774)
		(end 104.121966 -216.25052)
		(width 0.254)
		(layer "F.Cu")
		(net "GND")
	)
	(segment
		(start 409.748482 -249.166634)
		(end 410.853382 -249.166634)
		(width 0.381)
		(layer "F.Cu")
		(net "GND")
	)
	(segment
		(start 113.050066 -238.761524)
		(end 113.050066 -238.225838)
		(width 0.254)
		(layer "F.Cu")
		(net "GND")
	)
	(segment
		(start 102.712266 -230.622602)
		(end 102.712012 -230.622348)
		(width 0.2032)
		(layer "F.Cu")
		(net "GND")
	)
	(segment
		(start 204.076046 -268.71676)
		(end 205.180946 -268.71676)
		(width 0.381)
		(layer "F.Cu")
		(net "GND")
	)
	(segment
		(start 136.184894 -287.567116)
		(end 136.184894 -288.102802)
		(width 0.254)
		(layer "F.Cu")
		(net "GND")
	)
	(segment
		(start 124.437648 -262.87222)
		(end 124.437394 -262.872474)
		(width 0.254)
		(layer "F.Cu")
		(net "GND")
	)
	(segment
		(start 30.771846 -231.316784)
		(end 31.876746 -231.316784)
		(width 0.381)
		(layer "F.Cu")
		(net "GND")
	)
	(segment
		(start 348.77248 -243.644674)
		(end 348.77248 -243.108988)
		(width 0.254)
		(layer "F.Cu")
		(net "GND")
	)
	(segment
		(start 196.532246 -258.516628)
		(end 197.637146 -258.516628)
		(width 0.381)
		(layer "F.Cu")
		(net "GND")
	)
	(segment
		(start 92.844112 -234.156504)
		(end 92.844366 -234.15625)
		(width 0.254)
		(layer "F.Cu")
		(net "GND")
	)
	(segment
		(start 375.557034 -241.202972)
		(end 375.557034 -240.667286)
		(width 0.2032)
		(layer "F.Cu")
		(net "GND")
	)
	(segment
		(start 180.339746 -214.316564)
		(end 181.444646 -214.316564)
		(width 0.381)
		(layer "F.Cu")
		(net "GND")
	)
	(segment
		(start 358.170734 -217.600276)
		(end 358.170734 -217.064336)
		(width 0.2032)
		(layer "F.Cu")
		(net "GND")
	)
	(segment
		(start 362.039916 -265.592306)
		(end 362.039662 -266.128246)
		(width 0.2032)
		(layer "F.Cu")
		(net "GND")
	)
	(segment
		(start 285.211266 -365.651796)
		(end 285.645352 -365.21771)
		(width 0.2032)
		(layer "F.Cu")
		(net "GND")
	)
	(segment
		(start 29.666946 -263.616694)
		(end 30.771846 -263.616694)
		(width 0.381)
		(layer "F.Cu")
		(net "GND")
	)
	(segment
		(start 372.267734 -230.086916)
		(end 372.26748 -230.086662)
		(width 0.2032)
		(layer "F.Cu")
		(net "GND")
	)
	(segment
		(start 172.795946 -287.416748)
		(end 173.900846 -287.416748)
		(width 0.381)
		(layer "F.Cu")
		(net "GND")
	)
	(segment
		(start 88.725248 -262.87222)
		(end 88.724994 -262.872474)
		(width 0.2032)
		(layer "F.Cu")
		(net "GND")
	)
	(segment
		(start 159.918146 -221.96679)
		(end 158.813246 -221.96679)
		(width 0.381)
		(layer "F.Cu")
		(net "GND")
	)
	(segment
		(start 102.821994 -266.128246)
		(end 102.821994 -265.592306)
		(width 0.254)
		(layer "F.Cu")
		(net "GND")
	)
	(segment
		(start 286.255714 -212.616796)
		(end 287.360614 -212.616796)
		(width 0.381)
		(layer "F.Cu")
		(net "GND")
	)
	(segment
		(start 425.940982 -299.316648)
		(end 424.836082 -299.316648)
		(width 0.381)
		(layer "F.Cu")
		(net "GND")
	)
	(segment
		(start 215.719914 -316.316614)
		(end 216.824814 -316.316614)
		(width 0.381)
		(layer "F.Cu")
		(net "GND")
	)
	(segment
		(start 456.116182 -277.216616)
		(end 455.011282 -277.216616)
		(width 0.381)
		(layer "F.Cu")
		(net "GND")
	)
	(segment
		(start 410.853382 -238.116618)
		(end 409.527248 -238.116618)
		(width 0.381)
		(layer "F.Cu")
		(net "GND")
	)
	(segment
		(start 174.1424 -94.738698)
		(end 174.1424 -95.367348)
		(width 0.3556)
		(layer "F.Cu")
		(net "GND")
	)
	(segment
		(start 361.569762 -271.289272)
		(end 361.569762 -271.825212)
		(width 0.254)
		(layer "F.Cu")
		(net "GND")
	)
	(segment
		(start 307.782214 -317.166752)
		(end 308.887114 -317.166752)
		(width 0.381)
		(layer "F.Cu")
		(net "GND")
	)
	(segment
		(start 92.484702 -281.87015)
		(end 92.484448 -282.405836)
		(width 0.254)
		(layer "F.Cu")
		(net "GND")
	)
	(segment
		(start 435.823614 -208.366614)
		(end 436.928514 -208.366614)
		(width 0.381)
		(layer "F.Cu")
		(net "GND")
	)
	(segment
		(start 350.334834 -339.334602)
		(end 350.294956 -339.294724)
		(width 0.381)
		(layer "F.Cu")
		(net "GND")
	)
	(segment
		(start 298.62018 -56.432196)
		(end 297.88993 -56.432196)
		(width 0.3556)
		(layer "F.Cu")
		(net "GND")
	)
	(segment
		(start 352.531934 -214.344758)
		(end 352.531934 -213.732618)
		(width 0.254)
		(layer "F.Cu")
		(net "GND")
	)
	(segment
		(start 267.724382 -267.866622)
		(end 268.829282 -267.866622)
		(width 0.381)
		(layer "F.Cu")
		(net "GND")
	)
	(segment
		(start 116.339366 -220.041724)
		(end 116.339366 -219.506038)
		(width 0.254)
		(layer "F.Cu")
		(net "GND")
	)
	(segment
		(start 88.725248 -267.755624)
		(end 88.724994 -267.755878)
		(width 0.2032)
		(layer "F.Cu")
		(net "GND")
	)
	(segment
		(start 262.519414 -309.51678)
		(end 263.624314 -309.51678)
		(width 0.381)
		(layer "F.Cu")
		(net "GND")
	)
	(segment
		(start 436.928514 -214.316564)
		(end 438.033414 -214.316564)
		(width 0.381)
		(layer "F.Cu")
		(net "GND")
	)
	(segment
		(start 288.166048 -412.996126)
		(end 287.434528 -412.996126)
		(width 0.3556)
		(layer "F.Cu")
		(net "GND")
	)
	(segment
		(start 336.665316 -257.45313)
		(end 336.665316 -257.988816)
		(width 0.2032)
		(layer "F.Cu")
		(net "GND")
	)
	(segment
		(start 441.028582 -221.116652)
		(end 442.133482 -221.116652)
		(width 0.381)
		(layer "F.Cu")
		(net "GND")
	)
	(segment
		(start 141.656054 -94.887542)
		(end 141.656054 -93.757242)
		(width 0.3556)
		(layer "F.Cu")
		(net "GND")
	)
	(segment
		(start 127.726694 -259.894832)
		(end 127.726694 -260.430518)
		(width 0.254)
		(layer "F.Cu")
		(net "GND")
	)
	(segment
		(start 458.455014 -296.766742)
		(end 459.559914 -296.766742)
		(width 0.381)
		(layer "F.Cu")
		(net "GND")
	)
	(segment
		(start 376.606562 -255.011682)
		(end 376.606562 -255.547368)
		(width 0.2032)
		(layer "F.Cu")
		(net "GND")
	)
	(segment
		(start 429.384714 -240.666778)
		(end 430.489614 -240.666778)
		(width 0.381)
		(layer "F.Cu")
		(net "GND")
	)
	(segment
		(start 354.051616 -266.406122)
		(end 354.051616 -266.941808)
		(width 0.2032)
		(layer "F.Cu")
		(net "GND")
	)
	(segment
		(start 179.105814 -222.816674)
		(end 178.000914 -222.816674)
		(width 0.381)
		(layer "F.Cu")
		(net "GND")
	)
	(segment
		(start 48.526192 -354.022914)
		(end 48.13173 -353.628452)
		(width 0.2032)
		(layer "F.Cu")
		(net "GND")
	)
	(segment
		(start 129.74701 -12.495276)
		(end 129.74701 -13.600176)
		(width 0.3556)
		(layer "F.Cu")
		(net "GND")
	)
	(segment
		(start 204.076046 -201.56678)
		(end 205.180946 -201.56678)
		(width 0.381)
		(layer "F.Cu")
		(net "GND")
	)
	(segment
		(start 104.121712 -223.297496)
		(end 104.121712 -222.76181)
		(width 0.254)
		(layer "F.Cu")
		(net "GND")
	)
	(segment
		(start 346.063316 -271.011142)
		(end 346.063062 -271.011396)
		(width 0.2032)
		(layer "F.Cu")
		(net "GND")
	)
	(segment
		(start 213.4108 -107.01655)
		(end 214.4268 -107.01655)
		(width 0.3556)
		(layer "F.Cu")
		(net "GND")
	)
	(segment
		(start 263.624314 -217.716608)
		(end 264.729214 -217.716608)
		(width 0.381)
		(layer "F.Cu")
		(net "GND")
	)
	(segment
		(start 138.894312 -224.925382)
		(end 138.894312 -224.389696)
		(width 0.254)
		(layer "F.Cu")
		(net "GND")
	)
	(segment
		(start 7.035546 -267.016738)
		(end 8.140446 -267.016738)
		(width 0.381)
		(layer "F.Cu")
		(net "GND")
	)
	(segment
		(start 180.339746 -229.616762)
		(end 181.444646 -229.616762)
		(width 0.381)
		(layer "F.Cu")
		(net "GND")
	)
	(segment
		(start 207.071214 -284.866588)
		(end 208.176114 -284.866588)
		(width 0.381)
		(layer "F.Cu")
		(net "GND")
	)
	(segment
		(start 341.839804 -336.115406)
		(end 341.362792 -336.592418)
		(width 0.2032)
		(layer "F.Cu")
		(net "GND")
	)
	(segment
		(start 281.707082 -282.316682)
		(end 282.811982 -282.316682)
		(width 0.381)
		(layer "F.Cu")
		(net "GND")
	)
	(segment
		(start 291.460682 -291.666676)
		(end 290.355782 -291.666676)
		(width 0.381)
		(layer "F.Cu")
		(net "GND")
	)
	(segment
		(start 432.379882 -247.466612)
		(end 433.484782 -247.466612)
		(width 0.381)
		(layer "F.Cu")
		(net "GND")
	)
	(segment
		(start 405.648414 -270.416782)
		(end 406.753314 -270.416782)
		(width 0.381)
		(layer "F.Cu")
		(net "GND")
	)
	(segment
		(start 131.956048 -284.033468)
		(end 131.955794 -284.033722)
		(width 0.254)
		(layer "F.Cu")
		(net "GND")
	)
	(segment
		(start 347.363034 -239.575086)
		(end 347.363034 -239.0394)
		(width 0.2032)
		(layer "F.Cu")
		(net "GND")
	)
	(segment
		(start 334.315562 -268.033754)
		(end 335.255362 -268.569694)
		(width 0.2032)
		(layer "F.Cu")
		(net "GND")
	)
	(segment
		(start 374.257316 -283.497782)
		(end 374.257316 -284.033468)
		(width 0.254)
		(layer "F.Cu")
		(net "GND")
	)
	(segment
		(start 126.317248 -259.093462)
		(end 126.316994 -259.616956)
		(width 0.2032)
		(layer "F.Cu")
		(net "GND")
	)
	(segment
		(start 199.527414 -235.566712)
		(end 200.632314 -235.566712)
		(width 0.381)
		(layer "F.Cu")
		(net "GND")
	)
	(segment
		(start 420.736014 -199.01662)
		(end 421.840914 -199.01662)
		(width 0.381)
		(layer "F.Cu")
		(net "GND")
	)
	(segment
		(start 445.361822 -7.20471)
		(end 445.360552 -7.20344)
		(width 0.3556)
		(layer "F.Cu")
		(net "GND")
	)
	(segment
		(start 122.917712 -216.78646)
		(end 122.917712 -216.250774)
		(width 0.254)
		(layer "F.Cu")
		(net "GND")
	)
	(segment
		(start 385.424934 -250.155964)
		(end 386.047234 -250.155964)
		(width 0.254)
		(layer "F.Cu")
		(net "GND")
	)
	(segment
		(start 295.602406 -424.507152)
		(end 295.602406 -424.95597)
		(width 0.3556)
		(layer "F.Cu")
		(net "GND")
	)
	(segment
		(start 375.666762 -269.66164)
		(end 375.667016 -270.167862)
		(width 0.2032)
		(layer "F.Cu")
		(net "GND")
	)
	(segment
		(start 359.58018 -215.158574)
		(end 359.58018 -214.622888)
		(width 0.1778)
		(layer "F.Cu")
		(net "GND")
	)
	(segment
		(start 425.940982 -314.616592)
		(end 424.836082 -314.616592)
		(width 0.381)
		(layer "F.Cu")
		(net "GND")
	)
	(segment
		(start 188.988446 -260.21665)
		(end 187.883546 -260.21665)
		(width 0.381)
		(layer "F.Cu")
		(net "GND")
	)
	(segment
		(start 34.871914 -245.76659)
		(end 35.976814 -245.76659)
		(width 0.381)
		(layer "F.Cu")
		(net "GND")
	)
	(segment
		(start 367.678716 -283.497782)
		(end 367.678716 -284.033468)
		(width 0.254)
		(layer "F.Cu")
		(net "GND")
	)
	(segment
		(start 190.093346 -258.516628)
		(end 188.988446 -258.516628)
		(width 0.381)
		(layer "F.Cu")
		(net "GND")
	)
	(segment
		(start 101.412294 -256.639314)
		(end 101.412548 -256.639568)
		(width 0.2032)
		(layer "F.Cu")
		(net "GND")
	)
	(segment
		(start 244.75694 -247.396508)
		(end 244.4115 -247.051068)
		(width 0.3556)
		(layer "F.Cu")
		(net "GND")
	)
	(segment
		(start 66.00063 -116.488718)
		(end 66.00063 -117.123718)
		(width 0.381)
		(layer "F.Cu")
		(net "GND")
	)
	(segment
		(start 23.228046 -260.21665)
		(end 24.332946 -260.21665)
		(width 0.381)
		(layer "F.Cu")
		(net "GND")
	)
	(segment
		(start 126.786894 -285.939484)
		(end 126.786894 -286.475424)
		(width 0.254)
		(layer "F.Cu")
		(net "GND")
	)
	(segment
		(start 307.782214 -250.016772)
		(end 308.887114 -250.016772)
		(width 0.381)
		(layer "F.Cu")
		(net "GND")
	)
	(segment
		(start 57.503314 -286.56661)
		(end 58.608214 -286.56661)
		(width 0.381)
		(layer "F.Cu")
		(net "GND")
	)
	(segment
		(start 208.176114 -241.516662)
		(end 209.281014 -241.516662)
		(width 0.381)
		(layer "F.Cu")
		(net "GND")
	)
	(segment
		(start 60.947046 -234.716574)
		(end 62.051946 -234.716574)
		(width 0.381)
		(layer "F.Cu")
		(net "GND")
	)
	(segment
		(start 124.327666 -240.389156)
		(end 124.327412 -240.388902)
		(width 0.2032)
		(layer "F.Cu")
		(net "GND")
	)
	(segment
		(start 129.026666 -233.87812)
		(end 129.026412 -233.877866)
		(width 0.2032)
		(layer "F.Cu")
		(net "GND")
	)
	(segment
		(start 301.343314 -283.166566)
		(end 302.448214 -283.166566)
		(width 0.381)
		(layer "F.Cu")
		(net "GND")
	)
	(segment
		(start 138.894312 -236.319822)
		(end 139.364212 -236.597952)
		(width 0.254)
		(layer "F.Cu")
		(net "GND")
	)
	(segment
		(start 157.45587 -236.416596)
		(end 158.813246 -236.416596)
		(width 0.381)
		(layer "F.Cu")
		(net "GND")
	)
	(segment
		(start 153.613866 -108.361988)
		(end 153.613866 -107.660948)
		(width 0.3556)
		(layer "F.Cu")
		(net "GND")
	)
	(segment
		(start 22.123146 -309.51678)
		(end 23.228046 -309.51678)
		(width 0.381)
		(layer "F.Cu")
		(net "GND")
	)
	(segment
		(start 345.593162 -258.2672)
		(end 345.593162 -258.802886)
		(width 0.2032)
		(layer "F.Cu")
		(net "GND")
	)
	(segment
		(start 375.55678 -247.714262)
		(end 375.557034 -247.714008)
		(width 0.2032)
		(layer "F.Cu")
		(net "GND")
	)
	(segment
		(start 358.640634 -216.78646)
		(end 358.640634 -216.25052)
		(width 0.254)
		(layer "F.Cu")
		(net "GND")
	)
	(segment
		(start 108.820712 -234.69219)
		(end 108.820966 -234.691936)
		(width 0.254)
		(layer "F.Cu")
		(net "GND")
	)
	(segment
		(start 385.534662 -259.081016)
		(end 385.07797 -258.811268)
		(width 0.254)
		(layer "F.Cu")
		(net "GND")
	)
	(segment
		(start 358.280716 -271.011142)
		(end 358.280462 -271.011396)
		(width 0.254)
		(layer "F.Cu")
		(net "GND")
	)
	(segment
		(start 282.811982 -277.216616)
		(end 283.916882 -277.216616)
		(width 0.381)
		(layer "F.Cu")
		(net "GND")
	)
	(segment
		(start 35.976814 -282.316682)
		(end 34.871914 -282.316682)
		(width 0.381)
		(layer "F.Cu")
		(net "GND")
	)
	(segment
		(start 342.304116 -268.84757)
		(end 342.304116 -269.383256)
		(width 0.2032)
		(layer "F.Cu")
		(net "GND")
	)
	(segment
		(start 432.379882 -264.466578)
		(end 433.484782 -264.466578)
		(width 0.381)
		(layer "F.Cu")
		(net "GND")
	)
	(segment
		(start 375.557034 -220.041724)
		(end 375.557034 -219.506038)
		(width 0.254)
		(layer "F.Cu")
		(net "GND")
	)
	(segment
		(start 46.964346 -287.416748)
		(end 45.859446 -287.416748)
		(width 0.381)
		(layer "F.Cu")
		(net "GND")
	)
	(segment
		(start 204.076046 -229.616762)
		(end 205.180946 -229.616762)
		(width 0.381)
		(layer "F.Cu")
		(net "GND")
	)
	(segment
		(start 382.135634 -237.947454)
		(end 382.135634 -237.411514)
		(width 0.254)
		(layer "F.Cu")
		(net "GND")
	)
	(segment
		(start 129.136648 -268.84757)
		(end 129.136394 -269.38351)
		(width 0.2032)
		(layer "F.Cu")
		(net "GND")
	)
	(segment
		(start 302.895 -418.7063)
		(end 302.895 -418.069268)
		(width 0.3556)
		(layer "F.Cu")
		(net "GND")
	)
	(segment
		(start 456.116182 -204.116686)
		(end 455.011282 -204.116686)
		(width 0.381)
		(layer "F.Cu")
		(net "GND")
	)
	(segment
		(start 174.155608 -120.975374)
		(end 173.755558 -121.375424)
		(width 0.3556)
		(layer "F.Cu")
		(net "GND")
	)
	(segment
		(start 124.327666 -235.506006)
		(end 124.327412 -235.505752)
		(width 0.2032)
		(layer "F.Cu")
		(net "GND")
	)
	(segment
		(start 125.377448 -276.986492)
		(end 125.377448 -277.522432)
		(width 0.2032)
		(layer "F.Cu")
		(net "GND")
	)
	(segment
		(start 115.509294 -272.917158)
		(end 115.509294 -273.453098)
		(width 0.254)
		(layer "F.Cu")
		(net "GND")
	)
	(segment
		(start 308.887114 -304.416714)
		(end 309.992014 -304.416714)
		(width 0.381)
		(layer "F.Cu")
		(net "GND")
	)
	(segment
		(start 136.075166 -239.57534)
		(end 136.075166 -239.0394)
		(width 0.254)
		(layer "F.Cu")
		(net "GND")
	)
	(segment
		(start 129.496312 -229.808786)
		(end 129.496312 -229.272846)
		(width 0.2032)
		(layer "F.Cu")
		(net "GND")
	)
	(segment
		(start 437.515 -94.833948)
		(end 437.515 -94.471998)
		(width 0.3556)
		(layer "F.Cu")
		(net "GND")
	)
	(segment
		(start 204.076046 -242.3668)
		(end 205.180946 -242.3668)
		(width 0.381)
		(layer "F.Cu")
		(net "GND")
	)
	(segment
		(start 354.411534 -214.344758)
		(end 354.411534 -213.732618)
		(width 0.254)
		(layer "F.Cu")
		(net "GND")
	)
	(segment
		(start 282.811982 -202.416664)
		(end 283.916882 -202.416664)
		(width 0.381)
		(layer "F.Cu")
		(net "GND")
	)
	(segment
		(start 157.708346 -267.016738)
		(end 158.813246 -267.016738)
		(width 0.381)
		(layer "F.Cu")
		(net "GND")
	)
	(segment
		(start 276.373082 -228.766624)
		(end 275.268182 -228.766624)
		(width 0.381)
		(layer "F.Cu")
		(net "GND")
	)
	(segment
		(start 202.971146 -307.816758)
		(end 204.076046 -307.816758)
		(width 0.381)
		(layer "F.Cu")
		(net "GND")
	)
	(segment
		(start 56.182514 -207.51673)
		(end 57.503314 -207.51673)
		(width 0.381)
		(layer "F.Cu")
		(net "GND")
	)
	(segment
		(start 419.502082 -269.566644)
		(end 418.397182 -269.566644)
		(width 0.381)
		(layer "F.Cu")
		(net "GND")
	)
	(segment
		(start 301.343314 -276.366732)
		(end 302.664114 -276.366732)
		(width 0.381)
		(layer "F.Cu")
		(net "GND")
	)
	(segment
		(start 300.238414 -296.766742)
		(end 301.343314 -296.766742)
		(width 0.381)
		(layer "F.Cu")
		(net "GND")
	)
	(segment
		(start 60.947046 -258.516628)
		(end 62.051946 -258.516628)
		(width 0.381)
		(layer "F.Cu")
		(net "GND")
	)
	(segment
		(start 44.754546 -289.11677)
		(end 45.859446 -289.11677)
		(width 0.381)
		(layer "F.Cu")
		(net "GND")
	)
	(segment
		(start 188.988446 -240.666778)
		(end 187.883546 -240.666778)
		(width 0.381)
		(layer "F.Cu")
		(net "GND")
	)
	(segment
		(start 129.136648 -259.081016)
		(end 129.136648 -259.093462)
		(width 0.2032)
		(layer "F.Cu")
		(net "GND")
	)
	(segment
		(start 457.221082 -247.466612)
		(end 456.116182 -247.466612)
		(width 0.381)
		(layer "F.Cu")
		(net "GND")
	)
	(segment
		(start 24.368506 -129.870454)
		(end 24.368506 -130.26898)
		(width 0.381)
		(layer "F.Cu")
		(net "GND")
	)
	(segment
		(start 181.444646 -281.466798)
		(end 180.339746 -281.466798)
		(width 0.381)
		(layer "F.Cu")
		(net "GND")
	)
	(segment
		(start 433.484782 -207.51673)
		(end 434.589682 -207.51673)
		(width 0.381)
		(layer "F.Cu")
		(net "GND")
	)
	(segment
		(start 166.857934 -57.556908)
		(end 166.859204 -57.555638)
		(width 0.3556)
		(layer "F.Cu")
		(net "GND")
	)
	(segment
		(start 307.782214 -261.916672)
		(end 308.887114 -261.916672)
		(width 0.381)
		(layer "F.Cu")
		(net "GND")
	)
	(segment
		(start 366.32134 -335.886552)
		(end 366.66678 -335.541112)
		(width 0.2032)
		(layer "F.Cu")
		(net "GND")
	)
	(segment
		(start 373.317516 -283.497782)
		(end 373.317516 -284.033722)
		(width 0.254)
		(layer "F.Cu")
		(net "GND")
	)
	(segment
		(start 196.532246 -298.466764)
		(end 195.427346 -298.466764)
		(width 0.381)
		(layer "F.Cu")
		(net "GND")
	)
	(segment
		(start 385.534662 -281.869896)
		(end 385.534662 -282.405836)
		(width 0.254)
		(layer "F.Cu")
		(net "GND")
	)
	(segment
		(start 374.257316 -260.708902)
		(end 374.257316 -261.244588)
		(width 0.2032)
		(layer "F.Cu")
		(net "GND")
	)
	(segment
		(start 406.753314 -227.066602)
		(end 408.152092 -227.066602)
		(width 0.381)
		(layer "F.Cu")
		(net "GND")
	)
	(segment
		(start 355.821234 -229.808532)
		(end 355.821234 -229.272846)
		(width 0.2032)
		(layer "F.Cu")
		(net "GND")
	)
	(segment
		(start 95.773494 -279.96388)
		(end 95.773748 -279.964134)
		(width 0.254)
		(layer "F.Cu")
		(net "GND")
	)
	(segment
		(start 34.871914 -271.266666)
		(end 33.767014 -271.266666)
		(width 0.381)
		(layer "F.Cu")
		(net "GND")
	)
	(segment
		(start 377.90628 -235.505752)
		(end 377.90628 -234.970066)
		(width 0.2032)
		(layer "F.Cu")
		(net "GND")
	)
	(segment
		(start 349.24238 -222.76181)
		(end 349.242634 -222.761556)
		(width 0.254)
		(layer "F.Cu")
		(net "GND")
	)
	(segment
		(start 334.315562 -279.428194)
		(end 334.315562 -279.964134)
		(width 0.2032)
		(layer "F.Cu")
		(net "GND")
	)
	(segment
		(start 215.719914 -247.466612)
		(end 216.824814 -247.466612)
		(width 0.381)
		(layer "F.Cu")
		(net "GND")
	)
	(segment
		(start 286.255714 -281.466798)
		(end 287.360614 -281.466798)
		(width 0.381)
		(layer "F.Cu")
		(net "GND")
	)
	(segment
		(start 344.183716 -275.35886)
		(end 344.183716 -275.894546)
		(width 0.2032)
		(layer "F.Cu")
		(net "GND")
	)
	(segment
		(start 305.443382 -269.566644)
		(end 306.548282 -269.566644)
		(width 0.381)
		(layer "F.Cu")
		(net "GND")
	)
	(segment
		(start 104.701848 -276.986492)
		(end 104.701848 -277.521924)
		(width 0.2032)
		(layer "F.Cu")
		(net "GND")
	)
	(segment
		(start 160.43783 -120.106948)
		(end 159.82188 -120.106948)
		(width 0.3556)
		(layer "F.Cu")
		(net "GND")
	)
	(segment
		(start 100.832666 -232.250488)
		(end 100.832666 -231.714548)
		(width 0.2032)
		(layer "F.Cu")
		(net "GND")
	)
	(segment
		(start 349.24238 -226.553268)
		(end 349.24238 -226.017582)
		(width 0.254)
		(layer "F.Cu")
		(net "GND")
	)
	(segment
		(start 298.62018 -52.368196)
		(end 298.62018 -53.384196)
		(width 0.3556)
		(layer "F.Cu")
		(net "GND")
	)
	(segment
		(start 177.108104 -45.299884)
		(end 178.289204 -45.299884)
		(width 0.254)
		(layer "F.Cu")
		(net "GND")
	)
	(segment
		(start 12.240514 -267.866622)
		(end 13.345414 -267.866622)
		(width 0.381)
		(layer "F.Cu")
		(net "GND")
	)
	(segment
		(start 373.787162 -279.428194)
		(end 373.787416 -279.964134)
		(width 0.254)
		(layer "F.Cu")
		(net "GND")
	)
	(segment
		(start 419.730682 -272.966688)
		(end 418.397182 -272.966688)
		(width 0.381)
		(layer "F.Cu")
		(net "GND")
	)
	(segment
		(start 110.340648 -277.522178)
		(end 110.340394 -277.522432)
		(width 0.254)
		(layer "F.Cu")
		(net "GND")
	)
	(segment
		(start 214.615014 -213.46668)
		(end 215.719914 -213.46668)
		(width 0.381)
		(layer "F.Cu")
		(net "GND")
	)
	(segment
		(start 421.840914 -261.916672)
		(end 422.945814 -261.916672)
		(width 0.381)
		(layer "F.Cu")
		(net "GND")
	)
	(segment
		(start 308.887114 -261.916672)
		(end 309.992014 -261.916672)
		(width 0.381)
		(layer "F.Cu")
		(net "GND")
	)
	(segment
		(start 200.632314 -216.866724)
		(end 201.737214 -216.866724)
		(width 0.381)
		(layer "F.Cu")
		(net "GND")
	)
	(segment
		(start 372.847362 -255.011682)
		(end 372.847362 -255.547622)
		(width 0.2032)
		(layer "F.Cu")
		(net "GND")
	)
	(segment
		(start 175.005746 -234.716574)
		(end 173.900846 -234.716574)
		(width 0.381)
		(layer "F.Cu")
		(net "GND")
	)
	(segment
		(start 271.168114 -273.816572)
		(end 270.063214 -273.816572)
		(width 0.381)
		(layer "F.Cu")
		(net "GND")
	)
	(segment
		(start 295.721278 -364.60049)
		(end 296.074338 -364.60049)
		(width 0.2032)
		(layer "F.Cu")
		(net "GND")
	)
	(segment
		(start 111.170466 -228.45903)
		(end 111.170466 -228.99497)
		(width 0.2032)
		(layer "F.Cu")
		(net "GND")
	)
	(segment
		(start 162.913314 -244.066568)
		(end 164.018214 -244.066568)
		(width 0.381)
		(layer "F.Cu")
		(net "GND")
	)
	(segment
		(start 336.085434 -216.78646)
		(end 336.085434 -216.250774)
		(width 0.2032)
		(layer "F.Cu")
		(net "GND")
	)
	(segment
		(start 463.659982 -210.066636)
		(end 464.764882 -210.066636)
		(width 0.381)
		(layer "F.Cu")
		(net "GND")
	)
	(segment
		(start 340.78418 -242.295172)
		(end 340.784434 -242.294918)
		(width 0.2032)
		(layer "F.Cu")
		(net "GND")
	)
	(segment
		(start 338.90077 -39.295324)
		(end 337.900264 -39.295324)
		(width 0.2032)
		(layer "F.Cu")
		(net "GND")
	)
	(segment
		(start 405.648414 -251.716794)
		(end 406.753314 -251.716794)
		(width 0.381)
		(layer "F.Cu")
		(net "GND")
	)
	(segment
		(start 96.133666 -230.622602)
		(end 96.133412 -230.622348)
		(width 0.2032)
		(layer "F.Cu")
		(net "GND")
	)
	(segment
		(start 339.954362 -269.66164)
		(end 339.954362 -270.19758)
		(width 0.2032)
		(layer "F.Cu")
		(net "GND")
	)
	(segment
		(start 345.15171 -42.349928)
		(end 345.407234 -42.72915)
		(width 0.2032)
		(layer "F.Cu")
		(net "GND")
	)
	(segment
		(start 421.840914 -315.46673)
		(end 422.945814 -315.46673)
		(width 0.381)
		(layer "F.Cu")
		(net "GND")
	)
	(segment
		(start 208.176114 -216.866724)
		(end 209.281014 -216.866724)
		(width 0.381)
		(layer "F.Cu")
		(net "GND")
	)
	(segment
		(start 54.70398 -162.118548)
		(end 55.51678 -162.118548)
		(width 0.2032)
		(layer "F.Cu")
		(net "GND")
	)
	(segment
		(start 185.544714 -303.566576)
		(end 184.439814 -303.566576)
		(width 0.381)
		(layer "F.Cu")
		(net "GND")
	)
	(segment
		(start 53.403246 -195.616576)
		(end 54.508146 -195.616576)
		(width 0.381)
		(layer "F.Cu")
		(net "GND")
	)
	(segment
		(start 368.618516 -284.033468)
		(end 368.618262 -284.033722)
		(width 0.254)
		(layer "F.Cu")
		(net "GND")
	)
	(segment
		(start 261.285482 -269.566644)
		(end 260.180582 -269.566644)
		(width 0.381)
		(layer "F.Cu")
		(net "GND")
	)
	(segment
		(start 26.223214 -226.216718)
		(end 27.328114 -226.216718)
		(width 0.381)
		(layer "F.Cu")
		(net "GND")
	)
	(segment
		(start 370.85778 -246.08663)
		(end 370.858034 -246.086376)
		(width 0.2032)
		(layer "F.Cu")
		(net "GND")
	)
	(segment
		(start 458.455014 -283.166566)
		(end 459.559914 -283.166566)
		(width 0.381)
		(layer "F.Cu")
		(net "GND")
	)
	(segment
		(start 99.532694 -253.919482)
		(end 99.532948 -253.919736)
		(width 0.2032)
		(layer "F.Cu")
		(net "GND")
	)
	(segment
		(start 44.569634 -109.444282)
		(end 45.179234 -109.444282)
		(width 0.3556)
		(layer "F.Cu")
		(net "GND")
	)
	(segment
		(start 65.047114 -269.566644)
		(end 66.152014 -269.566644)
		(width 0.381)
		(layer "F.Cu")
		(net "GND")
	)
	(segment
		(start 181.444646 -208.366614)
		(end 182.549546 -208.366614)
		(width 0.381)
		(layer "F.Cu")
		(net "GND")
	)
	(segment
		(start 95.1484 -414.42894)
		(end 94.40926 -414.42894)
		(width 0.3556)
		(layer "F.Cu")
		(net "GND")
	)
	(segment
		(start 212.724746 -307.816758)
		(end 211.619846 -307.816758)
		(width 0.381)
		(layer "F.Cu")
		(net "GND")
	)
	(segment
		(start 337.02498 -247.714262)
		(end 337.02498 -247.178576)
		(width 0.2032)
		(layer "F.Cu")
		(net "GND")
	)
	(segment
		(start 418.397182 -310.366664)
		(end 417.015422 -310.366664)
		(width 0.381)
		(layer "F.Cu")
		(net "GND")
	)
	(segment
		(start 456.647804 -383.271268)
		(end 456.343258 -382.536446)
		(width 0.1778)
		(layer "F.Cu")
		(net "GND")
	)
	(segment
		(start 19.784314 -207.51673)
		(end 18.679414 -207.51673)
		(width 0.381)
		(layer "F.Cu")
		(net "GND")
	)
	(segment
		(start 136.184894 -262.058658)
		(end 136.184894 -261.522718)
		(width 0.254)
		(layer "F.Cu")
		(net "GND")
	)
	(segment
		(start 173.900846 -231.316784)
		(end 172.795946 -231.316784)
		(width 0.381)
		(layer "F.Cu")
		(net "GND")
	)
	(segment
		(start 26.223214 -305.266598)
		(end 27.328114 -305.266598)
		(width 0.381)
		(layer "F.Cu")
		(net "GND")
	)
	(segment
		(start 338.499958 -51.650646)
		(end 338.499958 -50.850546)
		(width 0.2032)
		(layer "F.Cu")
		(net "GND")
	)
	(segment
		(start 191.983614 -291.666676)
		(end 193.088514 -291.666676)
		(width 0.381)
		(layer "F.Cu")
		(net "GND")
	)
	(segment
		(start 340.894162 -253.383796)
		(end 340.894162 -253.919482)
		(width 0.2032)
		(layer "F.Cu")
		(net "GND")
	)
	(segment
		(start 191.983614 -305.266598)
		(end 193.088514 -305.266598)
		(width 0.381)
		(layer "F.Cu")
		(net "GND")
	)
	(segment
		(start 375.55678 -228.1809)
		(end 375.55678 -227.64496)
		(width 0.2032)
		(layer "F.Cu")
		(net "GND")
	)
	(segment
		(start 304.122582 -272.966688)
		(end 305.443382 -272.966688)
		(width 0.381)
		(layer "F.Cu")
		(net "GND")
	)
	(segment
		(start 340.784434 -233.06405)
		(end 340.784434 -232.528364)
		(width 0.254)
		(layer "F.Cu")
		(net "GND")
	)
	(segment
		(start 34.871914 -308.666642)
		(end 35.976814 -308.666642)
		(width 0.381)
		(layer "F.Cu")
		(net "GND")
	)
	(segment
		(start 304.338482 -249.166634)
		(end 305.443382 -249.166634)
		(width 0.381)
		(layer "F.Cu")
		(net "GND")
	)
	(segment
		(start 305.443382 -312.91657)
		(end 306.764182 -312.91657)
		(width 0.381)
		(layer "F.Cu")
		(net "GND")
	)
	(segment
		(start 52.72913 -162.016186)
		(end 52.500276 -162.016186)
		(width 0.2032)
		(layer "F.Cu")
		(net "GND")
	)
	(segment
		(start 86.265766 -229.808786)
		(end 86.735412 -230.086662)
		(width 0.2032)
		(layer "F.Cu")
		(net "GND")
	)
	(segment
		(start 110.340648 -275.894546)
		(end 110.340394 -275.8948)
		(width 0.254)
		(layer "F.Cu")
		(net "GND")
	)
	(segment
		(start 433.484782 -289.966654)
		(end 434.589682 -289.966654)
		(width 0.381)
		(layer "F.Cu")
		(net "GND")
	)
	(segment
		(start 414.297114 -251.716794)
		(end 415.402014 -251.716794)
		(width 0.381)
		(layer "F.Cu")
		(net "GND")
	)
	(segment
		(start 262.519414 -225.36658)
		(end 263.624314 -225.36658)
		(width 0.381)
		(layer "F.Cu")
		(net "GND")
	)
	(segment
		(start 113.629694 -282.683966)
		(end 113.629694 -283.219906)
		(width 0.254)
		(layer "F.Cu")
		(net "GND")
	)
	(segment
		(start 428.279814 -233.016806)
		(end 429.384714 -233.016806)
		(width 0.381)
		(layer "F.Cu")
		(net "GND")
	)
	(segment
		(start 353.111562 -284.311598)
		(end 353.111562 -284.847538)
		(width 0.254)
		(layer "F.Cu")
		(net "GND")
	)
	(segment
		(start 378.016516 -276.986492)
		(end 378.016516 -277.522432)
		(width 0.2032)
		(layer "F.Cu")
		(net "GND")
	)
	(segment
		(start 342.19388 -228.994716)
		(end 342.19388 -228.45903)
		(width 0.2032)
		(layer "F.Cu")
		(net "GND")
	)
	(segment
		(start 456.116182 -258.516628)
		(end 455.011282 -258.516628)
		(width 0.381)
		(layer "F.Cu")
		(net "GND")
	)
	(segment
		(start 370.498116 -262.336534)
		(end 370.498116 -262.872474)
		(width 0.2032)
		(layer "F.Cu")
		(net "GND")
	)
	(segment
		(start 89.555066 -238.761524)
		(end 89.554812 -238.76127)
		(width 0.254)
		(layer "F.Cu")
		(net "GND")
	)
	(segment
		(start 348.882716 -283.497782)
		(end 348.882716 -284.033468)
		(width 0.254)
		(layer "F.Cu")
		(net "GND")
	)
	(segment
		(start 45.859446 -225.36658)
		(end 46.964346 -225.36658)
		(width 0.381)
		(layer "F.Cu")
		(net "GND")
	)
	(segment
		(start 357.340662 -266.127992)
		(end 357.340916 -266.128246)
		(width 0.254)
		(layer "F.Cu")
		(net "GND")
	)
	(segment
		(start 372.73738 -220.041978)
		(end 372.737634 -220.041724)
		(width 0.254)
		(layer "F.Cu")
		(net "GND")
	)
	(segment
		(start 12.240514 -272.966688)
		(end 13.345414 -272.966688)
		(width 0.381)
		(layer "F.Cu")
		(net "GND")
	)
	(segment
		(start 181.444646 -229.616762)
		(end 182.549546 -229.616762)
		(width 0.381)
		(layer "F.Cu")
		(net "GND")
	)
	(segment
		(start 53.403246 -295.06672)
		(end 54.724046 -295.06672)
		(width 0.381)
		(layer "F.Cu")
		(net "GND")
	)
	(segment
		(start 104.701848 -285.125414)
		(end 104.701848 -285.6611)
		(width 0.254)
		(layer "F.Cu")
		(net "GND")
	)
	(segment
		(start 312.987182 -204.116686)
		(end 314.092082 -204.116686)
		(width 0.381)
		(layer "F.Cu")
		(net "GND")
	)
	(segment
		(start 272.273014 -298.466764)
		(end 271.168114 -298.466764)
		(width 0.381)
		(layer "F.Cu")
		(net "GND")
	)
	(segment
		(start 158.813246 -216.016586)
		(end 157.48127 -216.016586)
		(width 0.381)
		(layer "F.Cu")
		(net "GND")
	)
	(segment
		(start 138.534648 -278.614378)
		(end 139.004294 -278.336502)
		(width 0.254)
		(layer "F.Cu")
		(net "GND")
	)
	(segment
		(start 376.496834 -237.947454)
		(end 376.496834 -237.411514)
		(width 0.254)
		(layer "F.Cu")
		(net "GND")
	)
	(segment
		(start 345.483434 -249.341894)
		(end 345.483434 -248.806208)
		(width 0.2032)
		(layer "F.Cu")
		(net "GND")
	)
	(segment
		(start 445.577214 -300.166786)
		(end 444.472314 -300.166786)
		(width 0.381)
		(layer "F.Cu")
		(net "GND")
	)
	(segment
		(start 132.425694 -253.383796)
		(end 132.425694 -253.919736)
		(width 0.2032)
		(layer "F.Cu")
		(net "GND")
	)
	(segment
		(start 187.883546 -276.366732)
		(end 188.988446 -276.366732)
		(width 0.381)
		(layer "F.Cu")
		(net "GND")
	)
	(segment
		(start 169.123614 -272.966688)
		(end 170.457114 -272.966688)
		(width 0.381)
		(layer "F.Cu")
		(net "GND")
	)
	(segment
		(start 315.545978 -24.132032)
		(end 314.936378 -24.132032)
		(width 0.3556)
		(layer "F.Cu")
		(net "GND")
	)
	(segment
		(start 127.616712 -216.250774)
		(end 127.616966 -216.25052)
		(width 0.254)
		(layer "F.Cu")
		(net "GND")
	)
	(segment
		(start 274.163282 -249.166634)
		(end 275.268182 -249.166634)
		(width 0.381)
		(layer "F.Cu")
		(net "GND")
	)
	(segment
		(start 352.758502 -353.86264)
		(end 352.323146 -353.86264)
		(width 0.381)
		(layer "F.Cu")
		(net "GND")
	)
	(segment
		(start 338.90458 -244.458744)
		(end 338.904834 -244.45849)
		(width 0.2032)
		(layer "F.Cu")
		(net "GND")
	)
	(segment
		(start 358.280716 -273.730974)
		(end 358.280716 -274.26666)
		(width 0.254)
		(layer "F.Cu")
		(net "GND")
	)
	(segment
		(start 45.859446 -298.466764)
		(end 44.754546 -298.466764)
		(width 0.381)
		(layer "F.Cu")
		(net "GND")
	)
	(segment
		(start 105.641648 -277.521924)
		(end 105.641394 -277.522178)
		(width 0.2032)
		(layer "F.Cu")
		(net "GND")
	)
	(segment
		(start 183.878982 -35.836352)
		(end 183.878982 -35.195002)
		(width 0.3556)
		(layer "F.Cu")
		(net "GND")
	)
	(segment
		(start 90.494866 -230.086916)
		(end 90.494612 -230.086662)
		(width 0.254)
		(layer "F.Cu")
		(net "GND")
	)
	(segment
		(start 26.223214 -198.166736)
		(end 27.328114 -198.166736)
		(width 0.381)
		(layer "F.Cu")
		(net "GND")
	)
	(segment
		(start 429.384714 -204.96657)
		(end 430.489614 -204.96657)
		(width 0.381)
		(layer "F.Cu")
		(net "GND")
	)
	(segment
		(start 8.140446 -307.816758)
		(end 9.245346 -307.816758)
		(width 0.381)
		(layer "F.Cu")
		(net "GND")
	)
	(segment
		(start 297.899582 -210.066636)
		(end 299.004482 -210.066636)
		(width 0.381)
		(layer "F.Cu")
		(net "GND")
	)
	(segment
		(start 423.149014 -311.216802)
		(end 421.840914 -311.216802)
		(width 0.381)
		(layer "F.Cu")
		(net "GND")
	)
	(segment
		(start 101.882448 -283.497782)
		(end 101.882448 -284.033468)
		(width 0.254)
		(layer "F.Cu")
		(net "GND")
	)
	(segment
		(start 102.712266 -233.87812)
		(end 102.712012 -233.877866)
		(width 0.2032)
		(layer "F.Cu")
		(net "GND")
	)
	(segment
		(start 410.853382 -241.516662)
		(end 411.958282 -241.516662)
		(width 0.381)
		(layer "F.Cu")
		(net "GND")
	)
	(segment
		(start 182.549546 -313.766708)
		(end 181.444646 -313.766708)
		(width 0.381)
		(layer "F.Cu")
		(net "GND")
	)
	(segment
		(start 346.063316 -263.96442)
		(end 346.063316 -264.50036)
		(width 0.2032)
		(layer "F.Cu")
		(net "GND")
	)
	(segment
		(start 406.753314 -221.96679)
		(end 407.858214 -221.96679)
		(width 0.381)
		(layer "F.Cu")
		(net "GND")
	)
	(segment
		(start 334.205834 -246.08663)
		(end 334.205834 -245.55069)
		(width 0.2032)
		(layer "F.Cu")
		(net "GND")
	)
	(segment
		(start 162.913314 -303.566576)
		(end 161.808414 -303.566576)
		(width 0.381)
		(layer "F.Cu")
		(net "GND")
	)
	(segment
		(start 92.014294 -264.778236)
		(end 92.014294 -265.314176)
		(width 0.2032)
		(layer "F.Cu")
		(net "GND")
	)
	(segment
		(start 374.257316 -263.96442)
		(end 374.257316 -264.50036)
		(width 0.2032)
		(layer "F.Cu")
		(net "GND")
	)
	(segment
		(start 188.988446 -206.666592)
		(end 187.883546 -206.666592)
		(width 0.381)
		(layer "F.Cu")
		(net "GND")
	)
	(segment
		(start 185.544714 -269.566644)
		(end 186.649614 -269.566644)
		(width 0.381)
		(layer "F.Cu")
		(net "GND")
	)
	(segment
		(start 55.066946 -11.26998)
		(end 55.066946 -10.16508)
		(width 0.3556)
		(layer "F.Cu")
		(net "GND")
	)
	(segment
		(start 8.140446 -268.71676)
		(end 9.245346 -268.71676)
		(width 0.381)
		(layer "F.Cu")
		(net "GND")
	)
	(segment
		(start 436.928514 -309.51678)
		(end 438.033414 -309.51678)
		(width 0.381)
		(layer "F.Cu")
		(net "GND")
	)
	(segment
		(start 167.690546 -285.716726)
		(end 166.357046 -285.716726)
		(width 0.381)
		(layer "F.Cu")
		(net "GND")
	)
	(segment
		(start 414.297114 -225.36658)
		(end 415.402014 -225.36658)
		(width 0.381)
		(layer "F.Cu")
		(net "GND")
	)
	(segment
		(start 459.559914 -212.616796)
		(end 458.455014 -212.616796)
		(width 0.381)
		(layer "F.Cu")
		(net "GND")
	)
	(segment
		(start 188.988446 -313.766708)
		(end 190.093346 -313.766708)
		(width 0.381)
		(layer "F.Cu")
		(net "GND")
	)
	(segment
		(start 367.09858 -226.017582)
		(end 367.098834 -226.017328)
		(width 0.254)
		(layer "F.Cu")
		(net "GND")
	)
	(segment
		(start 54.724046 -210.916774)
		(end 53.403246 -210.916774)
		(width 0.381)
		(layer "F.Cu")
		(net "GND")
	)
	(segment
		(start 312.987182 -211.766658)
		(end 314.092082 -211.766658)
		(width 0.381)
		(layer "F.Cu")
		(net "GND")
	)
	(segment
		(start 381.19558 -223.297496)
		(end 381.19558 -222.76181)
		(width 0.254)
		(layer "F.Cu")
		(net "GND")
	)
	(segment
		(start 132.425694 -266.405868)
		(end 132.425694 -266.941808)
		(width 0.2032)
		(layer "F.Cu")
		(net "GND")
	)
	(segment
		(start 347.36278 -239.57534)
		(end 347.363034 -239.575086)
		(width 0.2032)
		(layer "F.Cu")
		(net "GND")
	)
	(segment
		(start 292.694614 -216.016586)
		(end 293.799514 -216.016586)
		(width 0.381)
		(layer "F.Cu")
		(net "GND")
	)
	(segment
		(start 122.939048 -360.443272)
		(end 121.984008 -360.443272)
		(width 0.3556)
		(layer "F.Cu")
		(net "GND")
	)
	(segment
		(start 126.786894 -274.54479)
		(end 126.786894 -275.08073)
		(width 0.2032)
		(layer "F.Cu")
		(net "GND")
	)
	(segment
		(start 63.726314 -216.866724)
		(end 65.047114 -216.866724)
		(width 0.381)
		(layer "F.Cu")
		(net "GND")
	)
	(segment
		(start 332.693518 -47.510446)
		(end 332.422246 -47.040546)
		(width 0.2032)
		(layer "F.Cu")
		(net "GND")
	)
	(segment
		(start 86.375494 -268.033754)
		(end 87.315294 -268.569694)
		(width 0.2032)
		(layer "F.Cu")
		(net "GND")
	)
	(segment
		(start 429.384714 -217.716608)
		(end 430.489614 -217.716608)
		(width 0.381)
		(layer "F.Cu")
		(net "GND")
	)
	(segment
		(start 208.176114 -261.066788)
		(end 209.281014 -261.066788)
		(width 0.381)
		(layer "F.Cu")
		(net "GND")
	)
	(segment
		(start 94.364048 -284.033468)
		(end 94.363794 -284.033722)
		(width 0.254)
		(layer "F.Cu")
		(net "GND")
	)
	(segment
		(start 29.031692 -415.366962)
		(end 29.666692 -415.366962)
		(width 0.3556)
		(layer "F.Cu")
		(net "GND")
	)
	(segment
		(start 420.736014 -204.96657)
		(end 421.840914 -204.96657)
		(width 0.381)
		(layer "F.Cu")
		(net "GND")
	)
	(segment
		(start 208.176114 -312.91657)
		(end 209.281014 -312.91657)
		(width 0.381)
		(layer "F.Cu")
		(net "GND")
	)
	(segment
		(start 448.572382 -241.516662)
		(end 447.467482 -241.516662)
		(width 0.381)
		(layer "F.Cu")
		(net "GND")
	)
	(segment
		(start 421.840914 -201.56678)
		(end 422.945814 -201.56678)
		(width 0.381)
		(layer "F.Cu")
		(net "GND")
	)
	(segment
		(start 99.532948 -268.034008)
		(end 99.532948 -268.569694)
		(width 0.2032)
		(layer "F.Cu")
		(net "GND")
	)
	(segment
		(start 368.03838 -223.297496)
		(end 368.03838 -222.76181)
		(width 0.254)
		(layer "F.Cu")
		(net "GND")
	)
	(segment
		(start 129.136648 -283.497782)
		(end 129.136648 -284.033468)
		(width 0.254)
		(layer "F.Cu")
		(net "GND")
	)
	(segment
		(start 89.664794 -262.336534)
		(end 89.664794 -262.872474)
		(width 0.2032)
		(layer "F.Cu")
		(net "GND")
	)
	(segment
		(start 348.77248 -248.527824)
		(end 348.77248 -247.992138)
		(width 0.2032)
		(layer "F.Cu")
		(net "GND")
	)
	(segment
		(start 165.252146 -204.96657)
		(end 166.357046 -204.96657)
		(width 0.381)
		(layer "F.Cu")
		(net "GND")
	)
	(segment
		(start 432.379882 -228.766624)
		(end 433.484782 -228.766624)
		(width 0.381)
		(layer "F.Cu")
		(net "GND")
	)
	(segment
		(start 405.4348 -217.716608)
		(end 406.753314 -217.716608)
		(width 0.381)
		(layer "F.Cu")
		(net "GND")
	)
	(segment
		(start 100.362766 -220.041724)
		(end 100.362766 -219.506038)
		(width 0.254)
		(layer "F.Cu")
		(net "GND")
	)
	(segment
		(start 448.29857 -76.695554)
		(end 448.668902 -76.325222)
		(width 0.254)
		(layer "F.Cu")
		(net "GND")
	)
	(segment
		(start 200.13295 -97.8662)
		(end 200.13295 -98.5266)
		(width 0.3556)
		(layer "F.Cu")
		(net "GND")
	)
	(segment
		(start 358.425496 -338.698078)
		(end 358.425496 -339.324696)
		(width 0.381)
		(layer "F.Cu")
		(net "GND")
	)
	(segment
		(start 282.811982 -213.46668)
		(end 283.916882 -213.46668)
		(width 0.381)
		(layer "F.Cu")
		(net "GND")
	)
	(segment
		(start 34.871914 -204.116686)
		(end 35.976814 -204.116686)
		(width 0.381)
		(layer "F.Cu")
		(net "GND")
	)
	(segment
		(start 371.327934 -214.344758)
		(end 371.327934 -213.732618)
		(width 0.254)
		(layer "F.Cu")
		(net "GND")
	)
	(segment
		(start 250.126754 -89.669112)
		(end 249.140726 -90.65514)
		(width 0.3556)
		(layer "F.Cu")
		(net "GND")
	)
	(segment
		(start 86.084918 -342.108028)
		(end 86.084918 -342.769952)
		(width 0.3556)
		(layer "F.Cu")
		(net "GND")
	)
	(segment
		(start 453.121014 -206.666592)
		(end 452.016114 -206.666592)
		(width 0.381)
		(layer "F.Cu")
		(net "GND")
	)
	(segment
		(start 32.361378 -97.554034)
		(end 31.751778 -97.554034)
		(width 0.3556)
		(layer "F.Cu")
		(net "GND")
	)
	(segment
		(start 165.252146 -309.51678)
		(end 166.357046 -309.51678)
		(width 0.381)
		(layer "F.Cu")
		(net "GND")
	)
	(segment
		(start 165.024054 -313.766708)
		(end 166.357046 -313.766708)
		(width 0.381)
		(layer "F.Cu")
		(net "GND")
	)
	(segment
		(start 352.062034 -231.436164)
		(end 352.062034 -230.900478)
		(width 0.2032)
		(layer "F.Cu")
		(net "GND")
	)
	(segment
		(start 419.502082 -306.96662)
		(end 418.397182 -306.96662)
		(width 0.381)
		(layer "F.Cu")
		(net "GND")
	)
	(segment
		(start 344.073734 -248.528078)
		(end 344.073734 -247.992138)
		(width 0.2032)
		(layer "F.Cu")
		(net "GND")
	)
	(segment
		(start 14.579346 -195.616576)
		(end 15.684246 -195.616576)
		(width 0.381)
		(layer "F.Cu")
		(net "GND")
	)
	(segment
		(start 91.544648 -283.497782)
		(end 91.544394 -283.498036)
		(width 0.254)
		(layer "F.Cu")
		(net "GND")
	)
	(segment
		(start 116.922042 -129.586482)
		(end 116.922042 -129.967482)
		(width 0.3556)
		(layer "F.Cu")
		(net "GND")
	)
	(segment
		(start 65.047114 -247.466612)
		(end 66.152014 -247.466612)
		(width 0.381)
		(layer "F.Cu")
		(net "GND")
	)
	(segment
		(start 382.245362 -263.68629)
		(end 382.245616 -263.686544)
		(width 0.2032)
		(layer "F.Cu")
		(net "GND")
	)
	(segment
		(start 115.76685 -104.465628)
		(end 115.75288 -104.479598)
		(width 0.3556)
		(layer "F.Cu")
		(net "GND")
	)
	(segment
		(start 89.084912 -220.041978)
		(end 89.085166 -220.041724)
		(width 0.254)
		(layer "F.Cu")
		(net "GND")
	)
	(segment
		(start 91.544648 -263.96442)
		(end 91.544648 -264.50036)
		(width 0.2032)
		(layer "F.Cu")
		(net "GND")
	)
	(segment
		(start 127.616966 -234.691936)
		(end 127.616966 -234.15625)
		(width 0.2032)
		(layer "F.Cu")
		(net "GND")
	)
	(segment
		(start 171.562014 -202.416664)
		(end 170.457114 -202.416664)
		(width 0.381)
		(layer "F.Cu")
		(net "GND")
	)
	(segment
		(start 60.947046 -298.466764)
		(end 62.051946 -298.466764)
		(width 0.381)
		(layer "F.Cu")
		(net "GND")
	)
	(segment
		(start 113.519966 -220.041724)
		(end 113.519966 -219.506038)
		(width 0.254)
		(layer "F.Cu")
		(net "GND")
	)
	(segment
		(start 260.180582 -198.166736)
		(end 259.075682 -198.166736)
		(width 0.381)
		(layer "F.Cu")
		(net "GND")
	)
	(segment
		(start 57.503314 -249.166634)
		(end 58.608214 -249.166634)
		(width 0.381)
		(layer "F.Cu")
		(net "GND")
	)
	(segment
		(start 118.218712 -231.436418)
		(end 118.218966 -231.436164)
		(width 0.2032)
		(layer "F.Cu")
		(net "GND")
	)
	(segment
		(start 374.147334 -238.761524)
		(end 374.147334 -238.225584)
		(width 0.2032)
		(layer "F.Cu")
		(net "GND")
	)
	(segment
		(start 215.719914 -226.216718)
		(end 216.824814 -226.216718)
		(width 0.381)
		(layer "F.Cu")
		(net "GND")
	)
	(segment
		(start 102.822248 -287.288986)
		(end 102.821994 -287.28924)
		(width 0.254)
		(layer "F.Cu")
		(net "GND")
	)
	(segment
		(start 185.544714 -258.516628)
		(end 186.649614 -258.516628)
		(width 0.381)
		(layer "F.Cu")
		(net "GND")
	)
	(segment
		(start 316.996572 -57.775348)
		(end 316.385956 -57.775348)
		(width 0.3556)
		(layer "F.Cu")
		(net "GND")
	)
	(segment
		(start 370.85778 -239.57534)
		(end 370.85778 -239.0394)
		(width 0.2032)
		(layer "F.Cu")
		(net "GND")
	)
	(segment
		(start 65.047114 -196.466714)
		(end 66.152014 -196.466714)
		(width 0.381)
		(layer "F.Cu")
		(net "GND")
	)
	(segment
		(start 349.352362 -258.2672)
		(end 349.352362 -258.80314)
		(width 0.254)
		(layer "F.Cu")
		(net "GND")
	)
	(segment
		(start 202.971146 -258.516628)
		(end 204.076046 -258.516628)
		(width 0.381)
		(layer "F.Cu")
		(net "GND")
	)
	(segment
		(start 26.223214 -266.1666)
		(end 27.328114 -266.1666)
		(width 0.381)
		(layer "F.Cu")
		(net "GND")
	)
	(segment
		(start 305.443382 -258.516628)
		(end 306.548282 -258.516628)
		(width 0.381)
		(layer "F.Cu")
		(net "GND")
	)
	(segment
		(start 125.737112 -216.250774)
		(end 125.737366 -216.25052)
		(width 0.254)
		(layer "F.Cu")
		(net "GND")
	)
	(segment
		(start 415.624264 -182.579518)
		(end 415.418778 -182.785004)
		(width 0.2032)
		(layer "F.Cu")
		(net "GND")
	)
	(segment
		(start 256.080514 -199.01662)
		(end 257.185414 -199.01662)
		(width 0.381)
		(layer "F.Cu")
		(net "GND")
	)
	(segment
		(start 119.158512 -216.78646)
		(end 119.158512 -216.250774)
		(width 0.254)
		(layer "F.Cu")
		(net "GND")
	)
	(segment
		(start 262.519414 -300.166786)
		(end 263.624314 -300.166786)
		(width 0.381)
		(layer "F.Cu")
		(net "GND")
	)
	(segment
		(start 57.503314 -258.516628)
		(end 56.398414 -258.516628)
		(width 0.381)
		(layer "F.Cu")
		(net "GND")
	)
	(segment
		(start 344.183716 -260.708902)
		(end 344.183716 -261.244588)
		(width 0.2032)
		(layer "F.Cu")
		(net "GND")
	)
	(segment
		(start 335.899252 -57.605168)
		(end 334.898746 -57.605168)
		(width 0.2032)
		(layer "F.Cu")
		(net "GND")
	)
	(segment
		(start 56.398414 -200.716642)
		(end 57.503314 -200.716642)
		(width 0.381)
		(layer "F.Cu")
		(net "GND")
	)
	(segment
		(start 193.088514 -232.166668)
		(end 191.983614 -232.166668)
		(width 0.381)
		(layer "F.Cu")
		(net "GND")
	)
	(segment
		(start 101.882448 -254.197612)
		(end 101.882448 -254.733044)
		(width 0.2032)
		(layer "F.Cu")
		(net "GND")
	)
	(segment
		(start 99.422966 -239.575086)
		(end 99.422966 -239.0394)
		(width 0.2032)
		(layer "F.Cu")
		(net "GND")
	)
	(segment
		(start 378.37618 -220.041978)
		(end 378.37618 -219.506292)
		(width 0.254)
		(layer "F.Cu")
		(net "GND")
	)
	(segment
		(start 419.735254 -238.116618)
		(end 418.397182 -238.116618)
		(width 0.381)
		(layer "F.Cu")
		(net "GND")
	)
	(segment
		(start 334.785716 -285.6611)
		(end 334.785462 -285.661354)
		(width 0.2032)
		(layer "F.Cu")
		(net "GND")
	)
	(segment
		(start 87.675466 -228.99497)
		(end 87.675466 -228.45903)
		(width 0.254)
		(layer "F.Cu")
		(net "GND")
	)
	(segment
		(start 395.885924 -49.749964)
		(end 397.765016 -49.749964)
		(width 0.254)
		(layer "F.Cu")
		(net "GND")
	)
	(segment
		(start 162.913314 -275.516594)
		(end 164.018214 -275.516594)
		(width 0.381)
		(layer "F.Cu")
		(net "GND")
	)
	(segment
		(start 191.983614 -289.966654)
		(end 193.088514 -289.966654)
		(width 0.381)
		(layer "F.Cu")
		(net "GND")
	)
	(segment
		(start 193.088514 -219.41663)
		(end 191.983614 -219.41663)
		(width 0.381)
		(layer "F.Cu")
		(net "GND")
	)
	(segment
		(start 377.546362 -272.917158)
		(end 377.546616 -273.453098)
		(width 0.2032)
		(layer "F.Cu")
		(net "GND")
	)
	(segment
		(start 408.061414 -283.166566)
		(end 406.753314 -283.166566)
		(width 0.381)
		(layer "F.Cu")
		(net "GND")
	)
	(segment
		(start 211.76361 -57.948322)
		(end 210.906106 -57.948322)
		(width 0.3556)
		(layer "F.Cu")
		(net "GND")
	)
	(segment
		(start 448.572382 -228.766624)
		(end 447.467482 -228.766624)
		(width 0.381)
		(layer "F.Cu")
		(net "GND")
	)
	(segment
		(start 376.966734 -243.644928)
		(end 376.96648 -243.644674)
		(width 0.2032)
		(layer "F.Cu")
		(net "GND")
	)
	(segment
		(start 53.403246 -238.966756)
		(end 54.508146 -238.966756)
		(width 0.381)
		(layer "F.Cu")
		(net "GND")
	)
	(segment
		(start 266.619482 -207.51673)
		(end 267.724382 -207.51673)
		(width 0.381)
		(layer "F.Cu")
		(net "GND")
	)
	(segment
		(start 7.035546 -290.816792)
		(end 8.140446 -290.816792)
		(width 0.381)
		(layer "F.Cu")
		(net "GND")
	)
	(segment
		(start 386.944362 -258.2672)
		(end 387.38556 -258.06654)
		(width 0.254)
		(layer "F.Cu")
		(net "GND")
	)
	(segment
		(start 418.397182 -316.316614)
		(end 417.292282 -316.316614)
		(width 0.381)
		(layer "F.Cu")
		(net "GND")
	)
	(segment
		(start 178.000914 -241.516662)
		(end 176.896014 -241.516662)
		(width 0.381)
		(layer "F.Cu")
		(net "GND")
	)
	(segment
		(start 187.883546 -306.116736)
		(end 188.988446 -306.116736)
		(width 0.381)
		(layer "F.Cu")
		(net "GND")
	)
	(segment
		(start 420.156894 -11.26998)
		(end 420.156894 -12.37488)
		(width 0.3556)
		(layer "F.Cu")
		(net "GND")
	)
	(segment
		(start 59.842146 -240.666778)
		(end 60.947046 -240.666778)
		(width 0.381)
		(layer "F.Cu")
		(net "GND")
	)
	(segment
		(start 385.424934 -227.367084)
		(end 384.485134 -226.831144)
		(width 0.254)
		(layer "F.Cu")
		(net "GND")
	)
	(segment
		(start 88.615012 -250.15571)
		(end 88.615012 -249.620024)
		(width 0.2032)
		(layer "F.Cu")
		(net "GND")
	)
	(segment
		(start 110.079282 -406.458166)
		(end 110.079282 -407.067766)
		(width 0.381)
		(layer "F.Cu")
		(net "GND")
	)
	(segment
		(start 420.736014 -263.616694)
		(end 421.840914 -263.616694)
		(width 0.381)
		(layer "F.Cu")
		(net "GND")
	)
	(segment
		(start 339.484716 -286.7533)
		(end 339.484716 -287.28924)
		(width 0.254)
		(layer "F.Cu")
		(net "GND")
	)
	(segment
		(start 289.250882 -211.766658)
		(end 290.355782 -211.766658)
		(width 0.381)
		(layer "F.Cu")
		(net "GND")
	)
	(segment
		(start 185.544714 -266.1666)
		(end 186.649614 -266.1666)
		(width 0.381)
		(layer "F.Cu")
		(net "GND")
	)
	(segment
		(start 212.724746 -285.716726)
		(end 211.619846 -285.716726)
		(width 0.381)
		(layer "F.Cu")
		(net "GND")
	)
	(segment
		(start 285.150814 -238.966756)
		(end 286.255714 -238.966756)
		(width 0.381)
		(layer "F.Cu")
		(net "GND")
	)
	(segment
		(start 159.918146 -281.466798)
		(end 158.813246 -281.466798)
		(width 0.381)
		(layer "F.Cu")
		(net "GND")
	)
	(segment
		(start 115.722908 -358.732836)
		(end 115.521994 -358.93375)
		(width 0.3556)
		(layer "F.Cu")
		(net "GND")
	)
	(segment
		(start 260.180582 -228.766624)
		(end 259.075682 -228.766624)
		(width 0.381)
		(layer "F.Cu")
		(net "GND")
	)
	(segment
		(start 444.472314 -217.716608)
		(end 443.367414 -217.716608)
		(width 0.381)
		(layer "F.Cu")
		(net "GND")
	)
	(segment
		(start 175.005746 -223.666558)
		(end 173.900846 -223.666558)
		(width 0.381)
		(layer "F.Cu")
		(net "GND")
	)
	(segment
		(start 456.116182 -314.616592)
		(end 455.011282 -314.616592)
		(width 0.381)
		(layer "F.Cu")
		(net "GND")
	)
	(segment
		(start 157.708346 -289.11677)
		(end 158.813246 -289.11677)
		(width 0.381)
		(layer "F.Cu")
		(net "GND")
	)
	(segment
		(start 349.352362 -277.800562)
		(end 349.352362 -278.336502)
		(width 0.2032)
		(layer "F.Cu")
		(net "GND")
	)
	(segment
		(start 165.252146 -270.416782)
		(end 166.357046 -270.416782)
		(width 0.381)
		(layer "F.Cu")
		(net "GND")
	)
	(segment
		(start 196.532246 -290.816792)
		(end 195.427346 -290.816792)
		(width 0.381)
		(layer "F.Cu")
		(net "GND")
	)
	(segment
		(start 429.384714 -260.21665)
		(end 430.489614 -260.21665)
		(width 0.381)
		(layer "F.Cu")
		(net "GND")
	)
	(segment
		(start 20.889214 -267.866622)
		(end 19.784314 -267.866622)
		(width 0.381)
		(layer "F.Cu")
		(net "GND")
	)
	(segment
		(start 123.497848 -283.497782)
		(end 123.497848 -284.033468)
		(width 0.254)
		(layer "F.Cu")
		(net "GND")
	)
	(segment
		(start 164.018214 -286.56661)
		(end 162.913314 -286.56661)
		(width 0.381)
		(layer "F.Cu")
		(net "GND")
	)
	(segment
		(start 308.887114 -223.666558)
		(end 307.782214 -223.666558)
		(width 0.381)
		(layer "F.Cu")
		(net "GND")
	)
	(segment
		(start 22.123146 -246.616728)
		(end 23.228046 -246.616728)
		(width 0.381)
		(layer "F.Cu")
		(net "GND")
	)
	(segment
		(start 278.474678 -419.916102)
		(end 278.0792 -420.31158)
		(width 0.3556)
		(layer "F.Cu")
		(net "GND")
	)
	(segment
		(start 40.256968 -11.26998)
		(end 40.256968 -12.37488)
		(width 0.3556)
		(layer "F.Cu")
		(net "GND")
	)
	(segment
		(start 198.20636 -119.121428)
		(end 197.98284 -119.344948)
		(width 0.3556)
		(layer "F.Cu")
		(net "GND")
	)
	(segment
		(start 329.89647 -57.605168)
		(end 330.396596 -58.020204)
		(width 0.2032)
		(layer "F.Cu")
		(net "GND")
	)
	(segment
		(start 386.474716 -257.45313)
		(end 386.474716 -257.98907)
		(width 0.254)
		(layer "F.Cu")
		(net "GND")
	)
	(segment
		(start 87.675466 -227.367084)
		(end 87.675466 -226.831144)
		(width 0.254)
		(layer "F.Cu")
		(net "GND")
	)
	(segment
		(start 82.322924 -153.021792)
		(end 81.455514 -153.021792)
		(width 0.3556)
		(layer "F.Cu")
		(net "GND")
	)
	(segment
		(start 428.279814 -217.716608)
		(end 429.384714 -217.716608)
		(width 0.381)
		(layer "F.Cu")
		(net "GND")
	)
	(segment
		(start 120.568212 -230.622348)
		(end 120.568212 -230.086662)
		(width 0.254)
		(layer "F.Cu")
		(net "GND")
	)
	(segment
		(start 165.252146 -208.366614)
		(end 166.357046 -208.366614)
		(width 0.381)
		(layer "F.Cu")
		(net "GND")
	)
	(segment
		(start 178.9557 -107.375452)
		(end 179.35575 -106.975402)
		(width 0.3556)
		(layer "F.Cu")
		(net "GND")
	)
	(segment
		(start 349.242634 -241.202972)
		(end 349.242634 -240.667286)
		(width 0.254)
		(layer "F.Cu")
		(net "GND")
	)
	(segment
		(start 377.90628 -250.15571)
		(end 377.90628 -249.620024)
		(width 0.2032)
		(layer "F.Cu")
		(net "GND")
	)
	(segment
		(start 363.919516 -273.730974)
		(end 363.919516 -274.266914)
		(width 0.254)
		(layer "F.Cu")
		(net "GND")
	)
	(segment
		(start 56.398414 -305.266598)
		(end 57.503314 -305.266598)
		(width 0.381)
		(layer "F.Cu")
		(net "GND")
	)
	(segment
		(start 33.767014 -207.51673)
		(end 34.871914 -207.51673)
		(width 0.381)
		(layer "F.Cu")
		(net "GND")
	)
	(segment
		(start 433.476908 -166.405814)
		(end 434.092858 -166.405814)
		(width 0.3556)
		(layer "F.Cu")
		(net "GND")
	)
	(segment
		(start 15.684246 -199.01662)
		(end 16.789146 -199.01662)
		(width 0.381)
		(layer "F.Cu")
		(net "GND")
	)
	(segment
		(start 276.373082 -278.916638)
		(end 275.268182 -278.916638)
		(width 0.381)
		(layer "F.Cu")
		(net "GND")
	)
	(segment
		(start 172.795946 -292.516814)
		(end 173.900846 -292.516814)
		(width 0.381)
		(layer "F.Cu")
		(net "GND")
	)
	(segment
		(start 413.192214 -248.31675)
		(end 414.297114 -248.31675)
		(width 0.381)
		(layer "F.Cu")
		(net "GND")
	)
	(segment
		(start 443.367414 -276.366732)
		(end 444.472314 -276.366732)
		(width 0.381)
		(layer "F.Cu")
		(net "GND")
	)
	(segment
		(start 300.238414 -238.966756)
		(end 301.343314 -238.966756)
		(width 0.381)
		(layer "F.Cu")
		(net "GND")
	)
	(segment
		(start 12.240514 -297.616626)
		(end 13.345414 -297.616626)
		(width 0.381)
		(layer "F.Cu")
		(net "GND")
	)
	(segment
		(start 370.38788 -237.133638)
		(end 370.38788 -236.597952)
		(width 0.254)
		(layer "F.Cu")
		(net "GND")
	)
	(segment
		(start 58.675524 -207.658716)
		(end 58.533538 -207.51673)
		(width 0.381)
		(layer "F.Cu")
		(net "GND")
	)
	(segment
		(start 345.37523 -59.914028)
		(end 345.143836 -59.682634)
		(width 0.2032)
		(layer "F.Cu")
		(net "GND")
	)
	(segment
		(start 382.715516 -285.125414)
		(end 382.715516 -285.6611)
		(width 0.2032)
		(layer "F.Cu")
		(net "GND")
	)
	(segment
		(start 296.794682 -230.466646)
		(end 297.899582 -230.466646)
		(width 0.381)
		(layer "F.Cu")
		(net "GND")
	)
	(segment
		(start 210.514946 -244.916706)
		(end 211.619846 -244.916706)
		(width 0.381)
		(layer "F.Cu")
		(net "GND")
	)
	(segment
		(start 14.579346 -236.416596)
		(end 15.684246 -236.416596)
		(width 0.381)
		(layer "F.Cu")
		(net "GND")
	)
	(segment
		(start 48.854614 -226.216718)
		(end 49.959514 -226.216718)
		(width 0.381)
		(layer "F.Cu")
		(net "GND")
	)
	(segment
		(start 40.256968 -10.16508)
		(end 40.256968 -11.26998)
		(width 0.3556)
		(layer "F.Cu")
		(net "GND")
	)
	(segment
		(start 12.240514 -226.216718)
		(end 13.345414 -226.216718)
		(width 0.381)
		(layer "F.Cu")
		(net "GND")
	)
	(segment
		(start 383.655062 -265.592306)
		(end 383.655062 -266.128246)
		(width 0.254)
		(layer "F.Cu")
		(net "GND")
	)
	(segment
		(start 179.755546 -111.375444)
		(end 180.155596 -110.975394)
		(width 0.3556)
		(layer "F.Cu")
		(net "GND")
	)
	(segment
		(start 102.712266 -224.111566)
		(end 102.712266 -223.575626)
		(width 0.2032)
		(layer "F.Cu")
		(net "GND")
	)
	(segment
		(start 65.047114 -224.516696)
		(end 66.152014 -224.516696)
		(width 0.381)
		(layer "F.Cu")
		(net "GND")
	)
	(segment
		(start 328.895964 -39.295324)
		(end 328.395584 -38.880288)
		(width 0.2032)
		(layer "F.Cu")
		(net "GND")
	)
	(segment
		(start 413.192214 -216.016586)
		(end 414.297114 -216.016586)
		(width 0.381)
		(layer "F.Cu")
		(net "GND")
	)
	(segment
		(start 308.887114 -267.016738)
		(end 309.992014 -267.016738)
		(width 0.381)
		(layer "F.Cu")
		(net "GND")
	)
	(segment
		(start 34.871914 -272.966688)
		(end 33.767014 -272.966688)
		(width 0.381)
		(layer "F.Cu")
		(net "GND")
	)
	(segment
		(start 366.268762 -279.428194)
		(end 366.268762 -279.964134)
		(width 0.254)
		(layer "F.Cu")
		(net "GND")
	)
	(segment
		(start 134.775448 -284.033468)
		(end 134.775194 -284.033722)
		(width 0.254)
		(layer "F.Cu")
		(net "GND")
	)
	(segment
		(start 421.840914 -285.716726)
		(end 420.736014 -285.716726)
		(width 0.381)
		(layer "F.Cu")
		(net "GND")
	)
	(segment
		(start 357.683816 -336.592418)
		(end 358.160828 -336.115406)
		(width 0.2032)
		(layer "F.Cu")
		(net "GND")
	)
	(segment
		(start 99.422966 -246.086376)
		(end 99.422966 -245.55069)
		(width 0.2032)
		(layer "F.Cu")
		(net "GND")
	)
	(segment
		(start 352.171762 -272.917158)
		(end 352.171762 -273.452844)
		(width 0.2032)
		(layer "F.Cu")
		(net "GND")
	)
	(segment
		(start 457.221082 -198.166736)
		(end 456.116182 -198.166736)
		(width 0.381)
		(layer "F.Cu")
		(net "GND")
	)
	(segment
		(start 405.648414 -250.016772)
		(end 406.753314 -250.016772)
		(width 0.381)
		(layer "F.Cu")
		(net "GND")
	)
	(segment
		(start 208.176114 -295.916604)
		(end 209.281014 -295.916604)
		(width 0.381)
		(layer "F.Cu")
		(net "GND")
	)
	(segment
		(start 63.942214 -194.766692)
		(end 65.047114 -194.766692)
		(width 0.381)
		(layer "F.Cu")
		(net "GND")
	)
	(segment
		(start 405.648414 -281.466798)
		(end 406.753314 -281.466798)
		(width 0.381)
		(layer "F.Cu")
		(net "GND")
	)
	(segment
		(start 126.317248 -261.244588)
		(end 126.316994 -261.244842)
		(width 0.2032)
		(layer "F.Cu")
		(net "GND")
	)
	(segment
		(start 104.701848 -273.730974)
		(end 104.701848 -274.26666)
		(width 0.2032)
		(layer "F.Cu")
		(net "GND")
	)
	(segment
		(start 56.398414 -264.466578)
		(end 57.503314 -264.466578)
		(width 0.381)
		(layer "F.Cu")
		(net "GND")
	)
	(segment
		(start 113.629694 -271.289272)
		(end 113.629694 -271.825212)
		(width 0.254)
		(layer "F.Cu")
		(net "GND")
	)
	(segment
		(start 44.754546 -231.316784)
		(end 45.859446 -231.316784)
		(width 0.381)
		(layer "F.Cu")
		(net "GND")
	)
	(segment
		(start 332.906116 -260.708902)
		(end 332.435962 -260.430772)
		(width 0.254)
		(layer "F.Cu")
		(net "GND")
	)
	(segment
		(start 131.016248 -280.242264)
		(end 131.015994 -280.778204)
		(width 0.254)
		(layer "F.Cu")
		(net "GND")
	)
	(segment
		(start 12.240514 -310.366664)
		(end 13.345414 -310.366664)
		(width 0.381)
		(layer "F.Cu")
		(net "GND")
	)
	(segment
		(start 282.811982 -278.916638)
		(end 283.916882 -278.916638)
		(width 0.381)
		(layer "F.Cu")
		(net "GND")
	)
	(segment
		(start 336.53603 -342.106758)
		(end 336.373216 -342.106758)
		(width 0.381)
		(layer "F.Cu")
		(net "GND")
	)
	(segment
		(start 332.906116 -263.96442)
		(end 332.905862 -264.50036)
		(width 0.254)
		(layer "F.Cu")
		(net "GND")
	)
	(segment
		(start 60.947046 -289.11677)
		(end 62.051946 -289.11677)
		(width 0.381)
		(layer "F.Cu")
		(net "GND")
	)
	(segment
		(start 339.484716 -270.475456)
		(end 339.484716 -271.011142)
		(width 0.2032)
		(layer "F.Cu")
		(net "GND")
	)
	(segment
		(start 59.842146 -222.04299)
		(end 59.918346 -221.96679)
		(width 0.381)
		(layer "F.Cu")
		(net "GND")
	)
	(segment
		(start 348.30258 -247.178576)
		(end 348.302834 -247.178322)
		(width 0.2032)
		(layer "F.Cu")
		(net "GND")
	)
	(segment
		(start 199.527414 -250.866656)
		(end 200.632314 -250.866656)
		(width 0.381)
		(layer "F.Cu")
		(net "GND")
	)
	(segment
		(start 376.96648 -228.994716)
		(end 376.96648 -228.45903)
		(width 0.2032)
		(layer "F.Cu")
		(net "GND")
	)
	(segment
		(start 346.532962 -279.96388)
		(end 346.533216 -279.964134)
		(width 0.254)
		(layer "F.Cu")
		(net "GND")
	)
	(segment
		(start 191.983614 -312.91657)
		(end 193.088514 -312.91657)
		(width 0.381)
		(layer "F.Cu")
		(net "GND")
	)
	(segment
		(start 337.49488 -242.016788)
		(end 337.49488 -241.481102)
		(width 0.2032)
		(layer "F.Cu")
		(net "GND")
	)
	(segment
		(start 57.503314 -278.916638)
		(end 58.608214 -278.916638)
		(width 0.381)
		(layer "F.Cu")
		(net "GND")
	)
	(segment
		(start 311.882282 -204.116686)
		(end 312.987182 -204.116686)
		(width 0.381)
		(layer "F.Cu")
		(net "GND")
	)
	(segment
		(start 88.615266 -225.739198)
		(end 88.615266 -225.203258)
		(width 0.2032)
		(layer "F.Cu")
		(net "GND")
	)
	(segment
		(start 12.240514 -303.566576)
		(end 13.345414 -303.566576)
		(width 0.381)
		(layer "F.Cu")
		(net "GND")
	)
	(segment
		(start 436.928514 -278.066754)
		(end 438.033414 -278.066754)
		(width 0.381)
		(layer "F.Cu")
		(net "GND")
	)
	(segment
		(start 32.947102 -8.320024)
		(end 32.947102 -9.424924)
		(width 0.3556)
		(layer "F.Cu")
		(net "GND")
	)
	(segment
		(start 188.988446 -300.166786)
		(end 187.883546 -300.166786)
		(width 0.381)
		(layer "F.Cu")
		(net "GND")
	)
	(segment
		(start 8.140446 -272.116804)
		(end 7.035546 -272.116804)
		(width 0.381)
		(layer "F.Cu")
		(net "GND")
	)
	(segment
		(start 382.245362 -263.150604)
		(end 382.245362 -263.68629)
		(width 0.2032)
		(layer "F.Cu")
		(net "GND")
	)
	(segment
		(start 289.250882 -224.516696)
		(end 290.355782 -224.516696)
		(width 0.381)
		(layer "F.Cu")
		(net "GND")
	)
	(segment
		(start 367.678716 -280.77795)
		(end 367.678462 -280.778204)
		(width 0.254)
		(layer "F.Cu")
		(net "GND")
	)
	(segment
		(start 188.988446 -201.56678)
		(end 187.883546 -201.56678)
		(width 0.381)
		(layer "F.Cu")
		(net "GND")
	)
	(segment
		(start 158.813246 -287.416748)
		(end 157.708346 -287.416748)
		(width 0.381)
		(layer "F.Cu")
		(net "GND")
	)
	(segment
		(start 43.520614 -213.46668)
		(end 42.415714 -213.46668)
		(width 0.381)
		(layer "F.Cu")
		(net "GND")
	)
	(segment
		(start 453.121014 -217.716608)
		(end 452.016114 -217.716608)
		(width 0.381)
		(layer "F.Cu")
		(net "GND")
	)
	(segment
		(start 335.299558 -50.050446)
		(end 335.699608 -50.450496)
		(width 0.2032)
		(layer "F.Cu")
		(net "GND")
	)
	(segment
		(start 276.373082 -275.516594)
		(end 275.268182 -275.516594)
		(width 0.381)
		(layer "F.Cu")
		(net "GND")
	)
	(segment
		(start 163.867084 -16.550132)
		(end 163.843462 -16.573754)
		(width 0.3556)
		(layer "F.Cu")
		(net "GND")
	)
	(segment
		(start 86.265766 -217.87866)
		(end 86.265512 -217.878406)
		(width 0.2032)
		(layer "F.Cu")
		(net "GND")
	)
	(segment
		(start 194.193414 -235.566712)
		(end 193.088514 -235.566712)
		(width 0.381)
		(layer "F.Cu")
		(net "GND")
	)
	(segment
		(start 334.675734 -217.06459)
		(end 334.67548 -217.064336)
		(width 0.2032)
		(layer "F.Cu")
		(net "GND")
	)
	(segment
		(start 381.19558 -242.295172)
		(end 381.195834 -242.294918)
		(width 0.2032)
		(layer "F.Cu")
		(net "GND")
	)
	(segment
		(start 267.724382 -264.466578)
		(end 268.829282 -264.466578)
		(width 0.381)
		(layer "F.Cu")
		(net "GND")
	)
	(segment
		(start 179.105814 -262.76681)
		(end 178.000914 -262.76681)
		(width 0.381)
		(layer "F.Cu")
		(net "GND")
	)
	(segment
		(start 306.473606 -207.51673)
		(end 305.443382 -207.51673)
		(width 0.381)
		(layer "F.Cu")
		(net "GND")
	)
	(segment
		(start 375.666762 -277.800562)
		(end 375.667016 -278.336502)
		(width 0.2032)
		(layer "F.Cu")
		(net "GND")
	)
	(segment
		(start 439.923682 -288.266632)
		(end 441.028582 -288.266632)
		(width 0.381)
		(layer "F.Cu")
		(net "GND")
	)
	(segment
		(start 299.700188 -387.147562)
		(end 299.700188 -390.459976)
		(width 0.4572)
		(layer "F.Cu")
		(net "GND")
	)
	(segment
		(start 107.881166 -229.808532)
		(end 107.881166 -229.272846)
		(width 0.2032)
		(layer "F.Cu")
		(net "GND")
	)
	(segment
		(start 101.412294 -271.289272)
		(end 101.412548 -271.289526)
		(width 0.2032)
		(layer "F.Cu")
		(net "GND")
	)
	(segment
		(start 172.795946 -307.816758)
		(end 173.900846 -307.816758)
		(width 0.381)
		(layer "F.Cu")
		(net "GND")
	)
	(segment
		(start 345.552776 -43.948096)
		(end 345.554554 -43.948096)
		(width 0.2032)
		(layer "F.Cu")
		(net "GND")
	)
	(segment
		(start 132.895848 -261.244588)
		(end 132.895594 -261.244842)
		(width 0.2032)
		(layer "F.Cu")
		(net "GND")
	)
	(segment
		(start 94.253812 -238.76127)
		(end 94.253812 -238.225584)
		(width 0.2032)
		(layer "F.Cu")
		(net "GND")
	)
	(segment
		(start 29.666946 -295.06672)
		(end 30.771846 -295.06672)
		(width 0.381)
		(layer "F.Cu")
		(net "GND")
	)
	(segment
		(start 91.434412 -246.900192)
		(end 91.434412 -246.364506)
		(width 0.2032)
		(layer "F.Cu")
		(net "GND")
	)
	(segment
		(start 165.60292 -33.990788)
		(end 165.429184 -34.164524)
		(width 0.3556)
		(layer "F.Cu")
		(net "GND")
	)
	(segment
		(start 369.91798 -226.017582)
		(end 369.918234 -226.017328)
		(width 0.254)
		(layer "F.Cu")
		(net "GND")
	)
	(segment
		(start 196.532246 -195.616576)
		(end 197.637146 -195.616576)
		(width 0.381)
		(layer "F.Cu")
		(net "GND")
	)
	(segment
		(start 135.245094 -279.96388)
		(end 135.24484 -279.964134)
		(width 0.254)
		(layer "F.Cu")
		(net "GND")
	)
	(segment
		(start 86.375494 -258.2672)
		(end 86.845394 -257.98907)
		(width 0.254)
		(layer "F.Cu")
		(net "GND")
	)
	(segment
		(start 382.135634 -230.900478)
		(end 382.135634 -231.436418)
		(width 0.2032)
		(layer "F.Cu")
		(net "GND")
	)
	(segment
		(start 120.678448 -284.033468)
		(end 120.678194 -284.033722)
		(width 0.254)
		(layer "F.Cu")
		(net "GND")
	)
	(segment
		(start 178.000914 -284.866588)
		(end 179.105814 -284.866588)
		(width 0.381)
		(layer "F.Cu")
		(net "GND")
	)
	(segment
		(start 276.373082 -280.61666)
		(end 275.268182 -280.61666)
		(width 0.381)
		(layer "F.Cu")
		(net "GND")
	)
	(segment
		(start 436.928514 -238.966756)
		(end 438.033414 -238.966756)
		(width 0.381)
		(layer "F.Cu")
		(net "GND")
	)
	(segment
		(start 397.43126 -168.478708)
		(end 397.803116 -168.106852)
		(width 0.381)
		(layer "F.Cu")
		(net "GND")
	)
	(segment
		(start 22.409404 -106.761026)
		(end 21.799804 -106.761026)
		(width 0.3556)
		(layer "F.Cu")
		(net "GND")
	)
	(segment
		(start 48.854614 -232.166668)
		(end 49.959514 -232.166668)
		(width 0.381)
		(layer "F.Cu")
		(net "GND")
	)
	(segment
		(start 159.918146 -220.266768)
		(end 158.813246 -220.266768)
		(width 0.381)
		(layer "F.Cu")
		(net "GND")
	)
	(segment
		(start 48.854614 -280.61666)
		(end 49.959514 -280.61666)
		(width 0.381)
		(layer "F.Cu")
		(net "GND")
	)
	(segment
		(start 297.899582 -198.166736)
		(end 299.004482 -198.166736)
		(width 0.381)
		(layer "F.Cu")
		(net "GND")
	)
	(segment
		(start 130.546094 -281.05608)
		(end 130.546348 -281.59202)
		(width 0.254)
		(layer "F.Cu")
		(net "GND")
	)
	(segment
		(start 165.252146 -263.616694)
		(end 166.357046 -263.616694)
		(width 0.381)
		(layer "F.Cu")
		(net "GND")
	)
	(segment
		(start 459.559914 -276.366732)
		(end 460.664814 -276.366732)
		(width 0.381)
		(layer "F.Cu")
		(net "GND")
	)
	(segment
		(start 211.619846 -313.766708)
		(end 210.514946 -313.766708)
		(width 0.381)
		(layer "F.Cu")
		(net "GND")
	)
	(segment
		(start 356.291134 -227.367084)
		(end 356.291134 -226.831144)
		(width 0.2032)
		(layer "F.Cu")
		(net "GND")
	)
	(segment
		(start 33.767014 -241.516662)
		(end 34.871914 -241.516662)
		(width 0.381)
		(layer "F.Cu")
		(net "GND")
	)
	(segment
		(start 59.842146 -306.116736)
		(end 60.947046 -306.116736)
		(width 0.381)
		(layer "F.Cu")
		(net "GND")
	)
	(segment
		(start 172.795946 -309.51678)
		(end 173.900846 -309.51678)
		(width 0.381)
		(layer "F.Cu")
		(net "GND")
	)
	(segment
		(start 296.794682 -291.666676)
		(end 297.899582 -291.666676)
		(width 0.381)
		(layer "F.Cu")
		(net "GND")
	)
	(segment
		(start 127.616712 -233.064304)
		(end 127.616712 -232.528618)
		(width 0.254)
		(layer "F.Cu")
		(net "GND")
	)
	(segment
		(start 433.484782 -244.066568)
		(end 434.589682 -244.066568)
		(width 0.381)
		(layer "F.Cu")
		(net "GND")
	)
	(segment
		(start 414.756854 -8.320024)
		(end 414.756854 -9.424924)
		(width 0.3556)
		(layer "F.Cu")
		(net "GND")
	)
	(segment
		(start 196.532246 -221.96679)
		(end 197.637146 -221.96679)
		(width 0.381)
		(layer "F.Cu")
		(net "GND")
	)
	(segment
		(start 444.472314 -295.06672)
		(end 445.577214 -295.06672)
		(width 0.381)
		(layer "F.Cu")
		(net "GND")
	)
	(segment
		(start 381.19558 -216.250774)
		(end 381.195834 -216.25052)
		(width 0.254)
		(layer "F.Cu")
		(net "GND")
	)
	(segment
		(start 207.071214 -278.916638)
		(end 208.176114 -278.916638)
		(width 0.381)
		(layer "F.Cu")
		(net "GND")
	)
	(segment
		(start 125.847094 -284.311598)
		(end 125.847348 -284.847538)
		(width 0.254)
		(layer "F.Cu")
		(net "GND")
	)
	(segment
		(start 452.016114 -273.816572)
		(end 450.911214 -273.816572)
		(width 0.381)
		(layer "F.Cu")
		(net "GND")
	)
	(segment
		(start 191.983614 -294.216582)
		(end 193.088514 -294.216582)
		(width 0.381)
		(layer "F.Cu")
		(net "GND")
	)
	(segment
		(start 43.520614 -204.116686)
		(end 42.415714 -204.116686)
		(width 0.381)
		(layer "F.Cu")
		(net "GND")
	)
	(segment
		(start 169.352214 -314.616592)
		(end 170.457114 -314.616592)
		(width 0.381)
		(layer "F.Cu")
		(net "GND")
	)
	(segment
		(start 342.66378 -244.458744)
		(end 342.66378 -243.922804)
		(width 0.2032)
		(layer "F.Cu")
		(net "GND")
	)
	(segment
		(start 344.63355 -53.149246)
		(end 344.36431 -52.679346)
		(width 0.254)
		(layer "F.Cu")
		(net "GND")
	)
	(segment
		(start 367.4364 -405.2316)
		(end 366.58677 -404.38197)
		(width 0.3556)
		(layer "F.Cu")
		(net "GND")
	)
	(segment
		(start 337.02498 -222.76181)
		(end 337.025234 -222.761556)
		(width 0.254)
		(layer "F.Cu")
		(net "GND")
	)
	(segment
		(start 345.48318 -216.250774)
		(end 345.483434 -216.25052)
		(width 0.254)
		(layer "F.Cu")
		(net "GND")
	)
	(segment
		(start 166.357046 -267.016738)
		(end 167.461946 -267.016738)
		(width 0.381)
		(layer "F.Cu")
		(net "GND")
	)
	(segment
		(start 89.555066 -225.203512)
		(end 89.554812 -225.203258)
		(width 0.2032)
		(layer "F.Cu")
		(net "GND")
	)
	(segment
		(start 262.519414 -195.616576)
		(end 263.624314 -195.616576)
		(width 0.381)
		(layer "F.Cu")
		(net "GND")
	)
	(segment
		(start 65.047114 -308.666642)
		(end 66.152014 -308.666642)
		(width 0.381)
		(layer "F.Cu")
		(net "GND")
	)
	(segment
		(start 204.076046 -270.416782)
		(end 205.180946 -270.416782)
		(width 0.381)
		(layer "F.Cu")
		(net "GND")
	)
	(segment
		(start 99.532694 -276.708362)
		(end 99.532948 -276.708616)
		(width 0.2032)
		(layer "F.Cu")
		(net "GND")
	)
	(segment
		(start 370.498116 -275.35886)
		(end 370.498116 -275.8948)
		(width 0.254)
		(layer "F.Cu")
		(net "GND")
	)
	(segment
		(start 99.422966 -249.341894)
		(end 99.422966 -248.806208)
		(width 0.2032)
		(layer "F.Cu")
		(net "GND")
	)
	(segment
		(start 53.07457 -162.361626)
		(end 52.72913 -162.016186)
		(width 0.2032)
		(layer "F.Cu")
		(net "GND")
	)
	(segment
		(start 312.987182 -198.166736)
		(end 314.092082 -198.166736)
		(width 0.381)
		(layer "F.Cu")
		(net "GND")
	)
	(segment
		(start 177.355754 -120.975374)
		(end 176.955704 -121.375424)
		(width 0.3556)
		(layer "F.Cu")
		(net "GND")
	)
	(segment
		(start 406.753314 -240.666778)
		(end 405.648414 -240.666778)
		(width 0.381)
		(layer "F.Cu")
		(net "GND")
	)
	(segment
		(start 307.566314 -276.366732)
		(end 308.887114 -276.366732)
		(width 0.381)
		(layer "F.Cu")
		(net "GND")
	)
	(segment
		(start 210.514946 -204.96657)
		(end 211.619846 -204.96657)
		(width 0.381)
		(layer "F.Cu")
		(net "GND")
	)
	(segment
		(start 57.503314 -198.166736)
		(end 58.608214 -198.166736)
		(width 0.381)
		(layer "F.Cu")
		(net "GND")
	)
	(segment
		(start 164.018214 -221.116652)
		(end 162.913314 -221.116652)
		(width 0.381)
		(layer "F.Cu")
		(net "GND")
	)
	(segment
		(start 459.559914 -304.416714)
		(end 460.664814 -304.416714)
		(width 0.381)
		(layer "F.Cu")
		(net "GND")
	)
	(segment
		(start 277.607014 -313.766708)
		(end 278.711914 -313.766708)
		(width 0.381)
		(layer "F.Cu")
		(net "GND")
	)
	(segment
		(start 359.110534 -219.228162)
		(end 359.110788 -219.227908)
		(width 0.254)
		(layer "F.Cu")
		(net "GND")
	)
	(segment
		(start 213.813644 -68.594732)
		(end 212.710268 -68.594732)
		(width 0.3556)
		(layer "F.Cu")
		(net "GND")
	)
	(segment
		(start 305.443382 -262.76681)
		(end 306.548282 -262.76681)
		(width 0.381)
		(layer "F.Cu")
		(net "GND")
	)
	(segment
		(start 345.270836 -53.236114)
		(end 345.270836 -53.669184)
		(width 0.254)
		(layer "F.Cu")
		(net "GND")
	)
	(segment
		(start 178.000914 -244.066568)
		(end 176.896014 -244.066568)
		(width 0.381)
		(layer "F.Cu")
		(net "GND")
	)
	(segment
		(start 199.527414 -308.666642)
		(end 200.632314 -308.666642)
		(width 0.381)
		(layer "F.Cu")
		(net "GND")
	)
	(segment
		(start 384.124962 -271.289272)
		(end 384.594862 -271.011396)
		(width 0.254)
		(layer "F.Cu")
		(net "GND")
	)
	(segment
		(start 362.54563 -408.544268)
		(end 363.2835 -408.544268)
		(width 0.3556)
		(layer "F.Cu")
		(net "GND")
	)
	(segment
		(start 63.942214 -289.966654)
		(end 65.047114 -289.966654)
		(width 0.381)
		(layer "F.Cu")
		(net "GND")
	)
	(segment
		(start 456.116182 -262.76681)
		(end 455.011282 -262.76681)
		(width 0.381)
		(layer "F.Cu")
		(net "GND")
	)
	(segment
		(start 195.427346 -268.71676)
		(end 196.532246 -268.71676)
		(width 0.381)
		(layer "F.Cu")
		(net "GND")
	)
	(segment
		(start 360.050334 -215.436958)
		(end 360.05008 -215.436704)
		(width 0.2032)
		(layer "F.Cu")
		(net "GND")
	)
	(segment
		(start 330.897738 -35.936936)
		(end 330.897738 -37.096192)
		(width 0.2032)
		(layer "F.Cu")
		(net "GND")
	)
	(segment
		(start 7.035546 -289.11677)
		(end 8.140446 -289.11677)
		(width 0.381)
		(layer "F.Cu")
		(net "GND")
	)
	(segment
		(start 363.809534 -217.600276)
		(end 363.809534 -217.064336)
		(width 0.254)
		(layer "F.Cu")
		(net "GND")
	)
	(segment
		(start 161.808414 -230.466646)
		(end 162.913314 -230.466646)
		(width 0.381)
		(layer "F.Cu")
		(net "GND")
	)
	(segment
		(start 370.498116 -268.84757)
		(end 370.497862 -269.38351)
		(width 0.254)
		(layer "F.Cu")
		(net "GND")
	)
	(segment
		(start 126.317248 -265.592306)
		(end 126.317248 -266.127992)
		(width 0.254)
		(layer "F.Cu")
		(net "GND")
	)
	(segment
		(start 101.772466 -250.155964)
		(end 101.772212 -250.15571)
		(width 0.2032)
		(layer "F.Cu")
		(net "GND")
	)
	(segment
		(start 49.917604 -153.644854)
		(end 49.290986 -153.644854)
		(width 0.381)
		(layer "F.Cu")
		(net "GND")
	)
	(segment
		(start 282.811982 -295.916604)
		(end 283.916882 -295.916604)
		(width 0.381)
		(layer "F.Cu")
		(net "GND")
	)
	(segment
		(start 175.31588 -130.666998)
		(end 175.31588 -131.280408)
		(width 0.3556)
		(layer "F.Cu")
		(net "GND")
	)
	(segment
		(start 7.035546 -292.516814)
		(end 8.140446 -292.516814)
		(width 0.381)
		(layer "F.Cu")
		(net "GND")
	)
	(segment
		(start 93.783912 -220.041978)
		(end 93.784166 -220.041724)
		(width 0.254)
		(layer "F.Cu")
		(net "GND")
	)
	(segment
		(start 124.437648 -266.127992)
		(end 124.437394 -266.128246)
		(width 0.254)
		(layer "F.Cu")
		(net "GND")
	)
	(segment
		(start 88.255094 -257.175254)
		(end 88.255094 -256.639314)
		(width 0.2032)
		(layer "F.Cu")
		(net "GND")
	)
	(segment
		(start 377.076716 -264.499852)
		(end 377.076462 -264.500106)
		(width 0.2032)
		(layer "F.Cu")
		(net "GND")
	)
	(segment
		(start 29.666946 -251.716794)
		(end 30.771846 -251.716794)
		(width 0.381)
		(layer "F.Cu")
		(net "GND")
	)
	(segment
		(start 178.614832 -355.953568)
		(end 178.614832 -355.723952)
		(width 0.2032)
		(layer "F.Cu")
		(net "GND")
	)
	(segment
		(start 333.26578 -242.830858)
		(end 333.26578 -242.294918)
		(width 0.254)
		(layer "F.Cu")
		(net "GND")
	)
	(segment
		(start 378.486162 -285.939484)
		(end 378.486162 -286.475424)
		(width 0.2032)
		(layer "F.Cu")
		(net "GND")
	)
	(segment
		(start 196.532246 -306.116736)
		(end 197.637146 -306.116736)
		(width 0.381)
		(layer "F.Cu")
		(net "GND")
	)
	(segment
		(start 204.076046 -204.96657)
		(end 205.180946 -204.96657)
		(width 0.381)
		(layer "F.Cu")
		(net "GND")
	)
	(segment
		(start 33.767014 -308.666642)
		(end 34.871914 -308.666642)
		(width 0.381)
		(layer "F.Cu")
		(net "GND")
	)
	(segment
		(start 44.905422 -401.967446)
		(end 44.905422 -402.633942)
		(width 0.3556)
		(layer "F.Cu")
		(net "GND")
	)
	(segment
		(start 387.493256 -270.470376)
		(end 387.493256 -270.4719)
		(width 0.254)
		(layer "F.Cu")
		(net "GND")
	)
	(segment
		(start 87.205312 -216.78646)
		(end 87.205312 -216.250774)
		(width 0.2032)
		(layer "F.Cu")
		(net "GND")
	)
	(segment
		(start 204.076046 -261.916672)
		(end 205.180946 -261.916672)
		(width 0.381)
		(layer "F.Cu")
		(net "GND")
	)
	(segment
		(start 197.637146 -313.766708)
		(end 196.532246 -313.766708)
		(width 0.381)
		(layer "F.Cu")
		(net "GND")
	)
	(segment
		(start 344.183716 -267.219938)
		(end 344.183462 -267.220192)
		(width 0.2032)
		(layer "F.Cu")
		(net "GND")
	)
	(segment
		(start 15.684246 -225.36658)
		(end 16.789146 -225.36658)
		(width 0.381)
		(layer "F.Cu")
		(net "GND")
	)
	(segment
		(start 14.426946 -395.247876)
		(end 15.036546 -395.247876)
		(width 0.3556)
		(layer "F.Cu")
		(net "GND")
	)
	(segment
		(start 289.250882 -230.466646)
		(end 290.355782 -230.466646)
		(width 0.381)
		(layer "F.Cu")
		(net "GND")
	)
	(segment
		(start 286.255714 -206.666592)
		(end 287.360614 -206.666592)
		(width 0.381)
		(layer "F.Cu")
		(net "GND")
	)
	(segment
		(start 360.05008 -237.133638)
		(end 360.05008 -236.597952)
		(width 0.2032)
		(layer "F.Cu")
		(net "GND")
	)
	(segment
		(start 424.836082 -200.716642)
		(end 425.940982 -200.716642)
		(width 0.381)
		(layer "F.Cu")
		(net "GND")
	)
	(segment
		(start 370.498116 -283.497782)
		(end 370.498116 -284.033468)
		(width 0.254)
		(layer "F.Cu")
		(net "GND")
	)
	(segment
		(start 338.904834 -220.041724)
		(end 338.904834 -219.506038)
		(width 0.254)
		(layer "F.Cu")
		(net "GND")
	)
	(segment
		(start 272.273014 -273.816572)
		(end 271.168114 -273.816572)
		(width 0.381)
		(layer "F.Cu")
		(net "GND")
	)
	(segment
		(start 276.373082 -247.466612)
		(end 275.268182 -247.466612)
		(width 0.381)
		(layer "F.Cu")
		(net "GND")
	)
	(segment
		(start 31.147004 -8.320024)
		(end 31.147004 -9.424924)
		(width 0.3556)
		(layer "F.Cu")
		(net "GND")
	)
	(segment
		(start 456.116182 -224.516696)
		(end 455.011282 -224.516696)
		(width 0.381)
		(layer "F.Cu")
		(net "GND")
	)
	(segment
		(start 348.772734 -236.598206)
		(end 348.77248 -236.597952)
		(width 0.254)
		(layer "F.Cu")
		(net "GND")
	)
	(segment
		(start 290.355782 -258.516628)
		(end 291.460682 -258.516628)
		(width 0.381)
		(layer "F.Cu")
		(net "GND")
	)
	(segment
		(start 96.133666 -250.155964)
		(end 96.133412 -250.15571)
		(width 0.2032)
		(layer "F.Cu")
		(net "GND")
	)
	(segment
		(start 208.176114 -228.766624)
		(end 209.281014 -228.766624)
		(width 0.381)
		(layer "F.Cu")
		(net "GND")
	)
	(segment
		(start 124.327666 -250.155964)
		(end 124.327412 -250.15571)
		(width 0.2032)
		(layer "F.Cu")
		(net "GND")
	)
	(segment
		(start 336.55508 -230.622348)
		(end 336.55508 -230.086662)
		(width 0.2032)
		(layer "F.Cu")
		(net "GND")
	)
	(segment
		(start 337.495134 -227.367084)
		(end 337.49488 -227.36683)
		(width 0.2032)
		(layer "F.Cu")
		(net "GND")
	)
	(segment
		(start 166.357046 -212.616796)
		(end 165.252146 -212.616796)
		(width 0.381)
		(layer "F.Cu")
		(net "GND")
	)
	(segment
		(start 300.279562 -423.954448)
		(end 300.637702 -423.954448)
		(width 0.3556)
		(layer "F.Cu")
		(net "GND")
	)
	(segment
		(start 286.255714 -217.716608)
		(end 287.360614 -217.716608)
		(width 0.381)
		(layer "F.Cu")
		(net "GND")
	)
	(segment
		(start 364.389416 -270.167862)
		(end 364.389416 -270.19758)
		(width 0.2032)
		(layer "F.Cu")
		(net "GND")
	)
	(segment
		(start 359.245154 -416.539934)
		(end 359.60304 -416.539934)
		(width 0.3556)
		(layer "F.Cu")
		(net "GND")
	)
	(segment
		(start 34.871914 -235.566712)
		(end 35.976814 -235.566712)
		(width 0.381)
		(layer "F.Cu")
		(net "GND")
	)
	(segment
		(start 301.343314 -273.816572)
		(end 302.664114 -273.816572)
		(width 0.381)
		(layer "F.Cu")
		(net "GND")
	)
	(segment
		(start 211.619846 -208.366614)
		(end 212.724746 -208.366614)
		(width 0.381)
		(layer "F.Cu")
		(net "GND")
	)
	(segment
		(start 91.544648 -261.244588)
		(end 91.544394 -261.244842)
		(width 0.2032)
		(layer "F.Cu")
		(net "GND")
	)
	(segment
		(start 127.616712 -228.1809)
		(end 127.616712 -227.64496)
		(width 0.2032)
		(layer "F.Cu")
		(net "GND")
	)
	(segment
		(start 161.808414 -294.216582)
		(end 162.913314 -294.216582)
		(width 0.381)
		(layer "F.Cu")
		(net "GND")
	)
	(segment
		(start 361.929934 -227.367084)
		(end 361.929934 -226.831144)
		(width 0.2032)
		(layer "F.Cu")
		(net "GND")
	)
	(segment
		(start 347.472762 -265.313922)
		(end 347.473016 -265.314176)
		(width 0.2032)
		(layer "F.Cu")
		(net "GND")
	)
	(segment
		(start 421.92194 -109.671358)
		(end 421.92194 -110.280958)
		(width 0.3556)
		(layer "F.Cu")
		(net "GND")
	)
	(segment
		(start 185.544714 -310.366664)
		(end 184.439814 -310.366664)
		(width 0.381)
		(layer "F.Cu")
		(net "GND")
	)
	(segment
		(start 341.833962 -269.66164)
		(end 341.834216 -269.661894)
		(width 0.2032)
		(layer "F.Cu")
		(net "GND")
	)
	(segment
		(start 52.298346 -263.616694)
		(end 53.403246 -263.616694)
		(width 0.381)
		(layer "F.Cu")
		(net "GND")
	)
	(segment
		(start 362.399834 -216.78646)
		(end 362.399834 -216.25052)
		(width 0.254)
		(layer "F.Cu")
		(net "GND")
	)
	(segment
		(start 139.482068 -246.900446)
		(end 139.624054 -247.042432)
		(width 0.2032)
		(layer "F.Cu")
		(net "GND")
	)
	(segment
		(start 414.297114 -217.716608)
		(end 415.402014 -217.716608)
		(width 0.381)
		(layer "F.Cu")
		(net "GND")
	)
	(segment
		(start 456.116182 -194.766692)
		(end 455.011282 -194.766692)
		(width 0.381)
		(layer "F.Cu")
		(net "GND")
	)
	(segment
		(start 282.811982 -261.066788)
		(end 283.916882 -261.066788)
		(width 0.381)
		(layer "F.Cu")
		(net "GND")
	)
	(segment
		(start 60.947046 -268.71676)
		(end 62.051946 -268.71676)
		(width 0.381)
		(layer "F.Cu")
		(net "GND")
	)
	(segment
		(start 275.268182 -249.166634)
		(end 276.373082 -249.166634)
		(width 0.381)
		(layer "F.Cu")
		(net "GND")
	)
	(segment
		(start 351.231962 -282.683966)
		(end 351.231962 -283.219906)
		(width 0.2032)
		(layer "F.Cu")
		(net "GND")
	)
	(segment
		(start 121.708926 -122.496834)
		(end 121.708926 -123.112784)
		(width 0.3556)
		(layer "F.Cu")
		(net "GND")
	)
	(segment
		(start 339.844634 -220.041724)
		(end 339.844634 -219.506038)
		(width 0.254)
		(layer "F.Cu")
		(net "GND")
	)
	(segment
		(start 427.045882 -299.316648)
		(end 425.940982 -299.316648)
		(width 0.381)
		(layer "F.Cu")
		(net "GND")
	)
	(segment
		(start 271.168114 -201.56678)
		(end 270.063214 -201.56678)
		(width 0.381)
		(layer "F.Cu")
		(net "GND")
	)
	(segment
		(start 208.176114 -278.916638)
		(end 209.281014 -278.916638)
		(width 0.381)
		(layer "F.Cu")
		(net "GND")
	)
	(segment
		(start 123.027948 -281.591766)
		(end 123.027948 -281.59202)
		(width 0.254)
		(layer "F.Cu")
		(net "GND")
	)
	(segment
		(start 262.519414 -278.066754)
		(end 263.624314 -278.066754)
		(width 0.381)
		(layer "F.Cu")
		(net "GND")
	)
	(segment
		(start 341.72398 -222.76181)
		(end 341.724234 -222.761556)
		(width 0.254)
		(layer "F.Cu")
		(net "GND")
	)
	(segment
		(start 91.074494 -263.68629)
		(end 91.074748 -263.686544)
		(width 0.2032)
		(layer "F.Cu")
		(net "GND")
	)
	(segment
		(start 380.835916 -280.242264)
		(end 380.835662 -280.242518)
		(width 0.254)
		(layer "F.Cu")
		(net "GND")
	)
	(segment
		(start 256.080514 -296.766742)
		(end 257.185414 -296.766742)
		(width 0.381)
		(layer "F.Cu")
		(net "GND")
	)
	(segment
		(start 345.48318 -236.319822)
		(end 345.48318 -235.783882)
		(width 0.2032)
		(layer "F.Cu")
		(net "GND")
	)
	(segment
		(start 89.554812 -242.016788)
		(end 89.554812 -241.481102)
		(width 0.2032)
		(layer "F.Cu")
		(net "GND")
	)
	(segment
		(start 296.794682 -249.166634)
		(end 297.899582 -249.166634)
		(width 0.381)
		(layer "F.Cu")
		(net "GND")
	)
	(segment
		(start 423.448734 -362.562648)
		(end 423.121582 -362.562648)
		(width 0.2032)
		(layer "F.Cu")
		(net "GND")
	)
	(segment
		(start 418.397182 -277.216616)
		(end 417.292282 -277.216616)
		(width 0.381)
		(layer "F.Cu")
		(net "GND")
	)
	(segment
		(start 282.811982 -239.81664)
		(end 283.916882 -239.81664)
		(width 0.381)
		(layer "F.Cu")
		(net "GND")
	)
	(segment
		(start 85.435694 -286.475424)
		(end 85.435694 -285.939484)
		(width 0.2032)
		(layer "F.Cu")
		(net "GND")
	)
	(segment
		(start 293.799514 -270.416782)
		(end 292.694614 -270.416782)
		(width 0.381)
		(layer "F.Cu")
		(net "GND")
	)
	(segment
		(start 100.942648 -254.197612)
		(end 100.942648 -254.733044)
		(width 0.2032)
		(layer "F.Cu")
		(net "GND")
	)
	(segment
		(start 300.238414 -242.3668)
		(end 301.343314 -242.3668)
		(width 0.381)
		(layer "F.Cu")
		(net "GND")
	)
	(segment
		(start 336.55508 -250.15571)
		(end 336.55508 -249.620024)
		(width 0.2032)
		(layer "F.Cu")
		(net "GND")
	)
	(segment
		(start 334.205834 -237.411768)
		(end 334.205834 -237.947454)
		(width 0.254)
		(layer "F.Cu")
		(net "GND")
	)
	(segment
		(start 339.014816 -268.034008)
		(end 339.014816 -268.569694)
		(width 0.2032)
		(layer "F.Cu")
		(net "GND")
	)
	(segment
		(start 63.726314 -219.41663)
		(end 65.047114 -219.41663)
		(width 0.381)
		(layer "F.Cu")
		(net "GND")
	)
	(segment
		(start 22.123146 -248.31675)
		(end 23.228046 -248.31675)
		(width 0.381)
		(layer "F.Cu")
		(net "GND")
	)
	(segment
		(start 165.252146 -265.316716)
		(end 166.357046 -265.316716)
		(width 0.381)
		(layer "F.Cu")
		(net "GND")
	)
	(segment
		(start 48.500284 -355.372924)
		(end 48.853344 -355.372924)
		(width 0.2032)
		(layer "F.Cu")
		(net "GND")
	)
	(segment
		(start 14.579346 -285.716726)
		(end 15.684246 -285.716726)
		(width 0.381)
		(layer "F.Cu")
		(net "GND")
	)
	(segment
		(start 98.013266 -243.644928)
		(end 98.013266 -243.108988)
		(width 0.2032)
		(layer "F.Cu")
		(net "GND")
	)
	(segment
		(start 200.632314 -207.51673)
		(end 201.737214 -207.51673)
		(width 0.381)
		(layer "F.Cu")
		(net "GND")
	)
	(segment
		(start 275.268182 -284.866588)
		(end 274.163282 -284.866588)
		(width 0.381)
		(layer "F.Cu")
		(net "GND")
	)
	(segment
		(start 290.355782 -205.816708)
		(end 291.460682 -205.816708)
		(width 0.381)
		(layer "F.Cu")
		(net "GND")
	)
	(segment
		(start 49.959514 -291.666676)
		(end 51.064414 -291.666676)
		(width 0.381)
		(layer "F.Cu")
		(net "GND")
	)
	(segment
		(start 301.343314 -250.016772)
		(end 302.448214 -250.016772)
		(width 0.381)
		(layer "F.Cu")
		(net "GND")
	)
	(segment
		(start 126.317248 -286.7533)
		(end 126.317248 -287.288986)
		(width 0.254)
		(layer "F.Cu")
		(net "GND")
	)
	(segment
		(start 15.684246 -221.96679)
		(end 14.579346 -221.96679)
		(width 0.381)
		(layer "F.Cu")
		(net "GND")
	)
	(segment
		(start 303.600612 -34.342832)
		(end 303.600612 -34.537396)
		(width 0.3556)
		(layer "F.Cu")
		(net "GND")
	)
	(segment
		(start 131.016248 -262.336534)
		(end 131.015994 -262.872474)
		(width 0.2032)
		(layer "F.Cu")
		(net "GND")
	)
	(segment
		(start 65.047114 -306.96662)
		(end 66.152014 -306.96662)
		(width 0.381)
		(layer "F.Cu")
		(net "GND")
	)
	(segment
		(start 380.725934 -237.133892)
		(end 380.72568 -236.597952)
		(width 0.2032)
		(layer "F.Cu")
		(net "GND")
	)
	(segment
		(start 359.110534 -233.87812)
		(end 359.11028 -233.877866)
		(width 0.2032)
		(layer "F.Cu")
		(net "GND")
	)
	(segment
		(start 342.304116 -254.197612)
		(end 342.773762 -253.919736)
		(width 0.2032)
		(layer "F.Cu")
		(net "GND")
	)
	(segment
		(start 414.297114 -238.966756)
		(end 415.402014 -238.966756)
		(width 0.381)
		(layer "F.Cu")
		(net "GND")
	)
	(segment
		(start 328.81062 -57.605168)
		(end 328.895964 -57.605168)
		(width 0.2032)
		(layer "F.Cu")
		(net "GND")
	)
	(segment
		(start 439.923682 -272.966688)
		(end 441.028582 -272.966688)
		(width 0.381)
		(layer "F.Cu")
		(net "GND")
	)
	(segment
		(start 23.228046 -238.966756)
		(end 24.332946 -238.966756)
		(width 0.381)
		(layer "F.Cu")
		(net "GND")
	)
	(segment
		(start 337.495134 -242.017042)
		(end 337.49488 -242.016788)
		(width 0.2032)
		(layer "F.Cu")
		(net "GND")
	)
	(segment
		(start 214.615014 -226.216718)
		(end 215.719914 -226.216718)
		(width 0.381)
		(layer "F.Cu")
		(net "GND")
	)
	(segment
		(start 354.991162 -278.336248)
		(end 354.991416 -278.336502)
		(width 0.254)
		(layer "F.Cu")
		(net "GND")
	)
	(segment
		(start 361.569762 -284.311598)
		(end 361.569762 -284.847538)
		(width 0.254)
		(layer "F.Cu")
		(net "GND")
	)
	(segment
		(start 44.754546 -236.416596)
		(end 45.859446 -236.416596)
		(width 0.381)
		(layer "F.Cu")
		(net "GND")
	)
	(segment
		(start 119.268494 -281.05608)
		(end 119.268748 -281.056334)
		(width 0.254)
		(layer "F.Cu")
		(net "GND")
	)
	(segment
		(start 193.088514 -222.816674)
		(end 191.983614 -222.816674)
		(width 0.381)
		(layer "F.Cu")
		(net "GND")
	)
	(segment
		(start 140.209524 -78.500478)
		(end 139.89304 -78.500478)
		(width 0.3556)
		(layer "F.Cu")
		(net "GND")
	)
	(segment
		(start 185.544714 -211.766658)
		(end 186.649614 -211.766658)
		(width 0.381)
		(layer "F.Cu")
		(net "GND")
	)
	(segment
		(start 312.987182 -224.516696)
		(end 314.092082 -224.516696)
		(width 0.381)
		(layer "F.Cu")
		(net "GND")
	)
	(segment
		(start 340.894416 -266.406122)
		(end 340.894416 -266.941808)
		(width 0.2032)
		(layer "F.Cu")
		(net "GND")
	)
	(segment
		(start 278.3586 -418.32149)
		(end 278.3586 -418.338)
		(width 0.3556)
		(layer "F.Cu")
		(net "GND")
	)
	(segment
		(start 34.871914 -233.86669)
		(end 35.976814 -233.86669)
		(width 0.381)
		(layer "F.Cu")
		(net "GND")
	)
	(segment
		(start 348.30258 -233.064304)
		(end 348.30258 -232.528618)
		(width 0.254)
		(layer "F.Cu")
		(net "GND")
	)
	(segment
		(start 455.986642 -382.17983)
		(end 455.986642 -381.69723)
		(width 0.1778)
		(layer "F.Cu")
		(net "GND")
	)
	(segment
		(start 182.549546 -217.716608)
		(end 181.444646 -217.716608)
		(width 0.381)
		(layer "F.Cu")
		(net "GND")
	)
	(segment
		(start 376.49658 -216.78646)
		(end 376.49658 -216.250774)
		(width 0.254)
		(layer "F.Cu")
		(net "GND")
	)
	(segment
		(start 345.123516 -287.288986)
		(end 345.123262 -287.28924)
		(width 0.254)
		(layer "F.Cu")
		(net "GND")
	)
	(segment
		(start 129.496312 -246.08663)
		(end 129.496566 -246.086376)
		(width 0.2032)
		(layer "F.Cu")
		(net "GND")
	)
	(segment
		(start 96.133412 -233.877866)
		(end 96.133412 -233.34218)
		(width 0.2032)
		(layer "F.Cu")
		(net "GND")
	)
	(segment
		(start 455.986642 -381.69723)
		(end 455.986642 -381.094488)
		(width 0.381)
		(layer "F.Cu")
		(net "GND")
	)
	(segment
		(start 116.449094 -288.102802)
		(end 116.449348 -288.103056)
		(width 0.254)
		(layer "F.Cu")
		(net "GND")
	)
	(segment
		(start 435.823614 -317.166752)
		(end 436.928514 -317.166752)
		(width 0.381)
		(layer "F.Cu")
		(net "GND")
	)
	(segment
		(start 200.632314 -310.366664)
		(end 201.737214 -310.366664)
		(width 0.381)
		(layer "F.Cu")
		(net "GND")
	)
	(segment
		(start 49.959514 -264.466578)
		(end 51.064414 -264.466578)
		(width 0.381)
		(layer "F.Cu")
		(net "GND")
	)
	(segment
		(start 297.899582 -288.266632)
		(end 299.004482 -288.266632)
		(width 0.381)
		(layer "F.Cu")
		(net "GND")
	)
	(segment
		(start 289.250882 -204.116686)
		(end 290.355782 -204.116686)
		(width 0.381)
		(layer "F.Cu")
		(net "GND")
	)
	(segment
		(start 104.121712 -226.017582)
		(end 104.121966 -226.017328)
		(width 0.254)
		(layer "F.Cu")
		(net "GND")
	)
	(segment
		(start 358.102662 -269.025624)
		(end 358.102662 -269.20571)
		(width 0.254)
		(layer "F.Cu")
		(net "GND")
	)
	(segment
		(start 185.544714 -233.86669)
		(end 186.649614 -233.86669)
		(width 0.381)
		(layer "F.Cu")
		(net "GND")
	)
	(segment
		(start 214.615014 -312.91657)
		(end 215.719914 -312.91657)
		(width 0.381)
		(layer "F.Cu")
		(net "GND")
	)
	(segment
		(start 210.143852 -125.476)
		(end 210.143852 -126.51105)
		(width 0.3556)
		(layer "F.Cu")
		(net "GND")
	)
	(segment
		(start 22.123146 -278.066754)
		(end 23.228046 -278.066754)
		(width 0.381)
		(layer "F.Cu")
		(net "GND")
	)
	(segment
		(start 256.080514 -223.666558)
		(end 257.185414 -223.666558)
		(width 0.381)
		(layer "F.Cu")
		(net "GND")
	)
	(segment
		(start 424.836082 -271.266666)
		(end 425.940982 -271.266666)
		(width 0.381)
		(layer "F.Cu")
		(net "GND")
	)
	(segment
		(start 94.254066 -248.528078)
		(end 94.253812 -248.527824)
		(width 0.2032)
		(layer "F.Cu")
		(net "GND")
	)
	(segment
		(start 384.595116 -267.755624)
		(end 384.594862 -267.755878)
		(width 0.254)
		(layer "F.Cu")
		(net "GND")
	)
	(segment
		(start 30.771846 -278.066754)
		(end 31.876746 -278.066754)
		(width 0.381)
		(layer "F.Cu")
		(net "GND")
	)
	(segment
		(start 22.123146 -217.716608)
		(end 23.228046 -217.716608)
		(width 0.381)
		(layer "F.Cu")
		(net "GND")
	)
	(segment
		(start 148.91258 -39.693088)
		(end 150.53056 -39.693088)
		(width 0.3556)
		(layer "F.Cu")
		(net "GND")
	)
	(segment
		(start 184.439814 -280.61666)
		(end 185.544714 -280.61666)
		(width 0.381)
		(layer "F.Cu")
		(net "GND")
	)
	(segment
		(start 23.228046 -233.016806)
		(end 24.332946 -233.016806)
		(width 0.381)
		(layer "F.Cu")
		(net "GND")
	)
	(segment
		(start 421.840914 -204.96657)
		(end 422.945814 -204.96657)
		(width 0.381)
		(layer "F.Cu")
		(net "GND")
	)
	(segment
		(start 425.940982 -230.466646)
		(end 424.836082 -230.466646)
		(width 0.381)
		(layer "F.Cu")
		(net "GND")
	)
	(segment
		(start 256.080514 -229.616762)
		(end 257.185414 -229.616762)
		(width 0.381)
		(layer "F.Cu")
		(net "GND")
	)
	(segment
		(start 215.73617 -19.517614)
		(end 216.788238 -20.569682)
		(width 0.3556)
		(layer "F.Cu")
		(net "GND")
	)
	(segment
		(start 449.677282 -204.116686)
		(end 448.572382 -204.116686)
		(width 0.381)
		(layer "F.Cu")
		(net "GND")
	)
	(segment
		(start 338.544916 -281.869896)
		(end 338.54517 -281.87015)
		(width 0.254)
		(layer "F.Cu")
		(net "GND")
	)
	(segment
		(start 211.619846 -212.616796)
		(end 212.724746 -212.616796)
		(width 0.381)
		(layer "F.Cu")
		(net "GND")
	)
	(segment
		(start 254.975614 -225.36658)
		(end 256.080514 -225.36658)
		(width 0.381)
		(layer "F.Cu")
		(net "GND")
	)
	(segment
		(start 349.712534 -246.900446)
		(end 349.712534 -246.36476)
		(width 0.2032)
		(layer "F.Cu")
		(net "GND")
	)
	(segment
		(start 100.362512 -247.714262)
		(end 100.362512 -247.178576)
		(width 0.2032)
		(layer "F.Cu")
		(net "GND")
	)
	(segment
		(start 362.979716 -277.522178)
		(end 362.979462 -277.522432)
		(width 0.254)
		(layer "F.Cu")
		(net "GND")
	)
	(segment
		(start 127.147066 -220.855794)
		(end 127.147066 -220.319854)
		(width 0.2032)
		(layer "F.Cu")
		(net "GND")
	)
	(segment
		(start 200.632314 -269.566644)
		(end 201.737214 -269.566644)
		(width 0.381)
		(layer "F.Cu")
		(net "GND")
	)
	(segment
		(start 385.534662 -257.988816)
		(end 385.534916 -257.98907)
		(width 0.254)
		(layer "F.Cu")
		(net "GND")
	)
	(segment
		(start 336.665316 -287.288986)
		(end 336.665062 -287.28924)
		(width 0.254)
		(layer "F.Cu")
		(net "GND")
	)
	(segment
		(start 457.221082 -286.56661)
		(end 456.116182 -286.56661)
		(width 0.381)
		(layer "F.Cu")
		(net "GND")
	)
	(segment
		(start 88.145366 -236.319822)
		(end 88.145366 -235.783882)
		(width 0.254)
		(layer "F.Cu")
		(net "GND")
	)
	(segment
		(start 345.48318 -223.297496)
		(end 345.48318 -222.76181)
		(width 0.254)
		(layer "F.Cu")
		(net "GND")
	)
	(segment
		(start 137.023602 -248.794524)
		(end 137.022586 -248.798588)
		(width 0.254)
		(layer "F.Cu")
		(net "GND")
	)
	(segment
		(start 370.027962 -281.05608)
		(end 370.028216 -281.59202)
		(width 0.254)
		(layer "F.Cu")
		(net "GND")
	)
	(segment
		(start 196.532246 -276.366732)
		(end 195.427346 -276.366732)
		(width 0.381)
		(layer "F.Cu")
		(net "GND")
	)
	(segment
		(start 335.255362 -269.66164)
		(end 335.255362 -270.19758)
		(width 0.2032)
		(layer "F.Cu")
		(net "GND")
	)
	(segment
		(start 402.046948 -8.320024)
		(end 402.046948 -9.424924)
		(width 0.3556)
		(layer "F.Cu")
		(net "GND")
	)
	(segment
		(start 281.707082 -312.91657)
		(end 282.811982 -312.91657)
		(width 0.381)
		(layer "F.Cu")
		(net "GND")
	)
	(segment
		(start 57.503314 -305.266598)
		(end 58.608214 -305.266598)
		(width 0.381)
		(layer "F.Cu")
		(net "GND")
	)
	(segment
		(start 33.767014 -235.566712)
		(end 34.871914 -235.566712)
		(width 0.381)
		(layer "F.Cu")
		(net "GND")
	)
	(segment
		(start 49.959514 -258.516628)
		(end 51.064414 -258.516628)
		(width 0.381)
		(layer "F.Cu")
		(net "GND")
	)
	(segment
		(start 420.736014 -216.016586)
		(end 421.840914 -216.016586)
		(width 0.381)
		(layer "F.Cu")
		(net "GND")
	)
	(segment
		(start 98.123248 -275.35886)
		(end 98.123248 -275.894546)
		(width 0.2032)
		(layer "F.Cu")
		(net "GND")
	)
	(segment
		(start 98.592894 -264.778236)
		(end 98.592894 -265.314176)
		(width 0.2032)
		(layer "F.Cu")
		(net "GND")
	)
	(segment
		(start 98.013266 -228.45903)
		(end 98.013266 -228.99497)
		(width 0.2032)
		(layer "F.Cu")
		(net "GND")
	)
	(segment
		(start 44.754546 -309.51678)
		(end 45.859446 -309.51678)
		(width 0.381)
		(layer "F.Cu")
		(net "GND")
	)
	(segment
		(start 425.940982 -238.116618)
		(end 427.045882 -238.116618)
		(width 0.381)
		(layer "F.Cu")
		(net "GND")
	)
	(segment
		(start 344.073734 -235.506006)
		(end 344.07348 -235.505752)
		(width 0.2032)
		(layer "F.Cu")
		(net "GND")
	)
	(segment
		(start 297.485562 -423.954448)
		(end 297.843702 -423.954448)
		(width 0.3556)
		(layer "F.Cu")
		(net "GND")
	)
	(segment
		(start 194.193414 -200.716642)
		(end 193.088514 -200.716642)
		(width 0.381)
		(layer "F.Cu")
		(net "GND")
	)
	(segment
		(start 48.854614 -278.916638)
		(end 49.959514 -278.916638)
		(width 0.381)
		(layer "F.Cu")
		(net "GND")
	)
	(segment
		(start 460.664814 -223.666558)
		(end 459.559914 -223.666558)
		(width 0.381)
		(layer "F.Cu")
		(net "GND")
	)
	(segment
		(start 210.514946 -279.766776)
		(end 211.619846 -279.766776)
		(width 0.381)
		(layer "F.Cu")
		(net "GND")
	)
	(segment
		(start 432.379882 -245.76659)
		(end 433.484782 -245.76659)
		(width 0.381)
		(layer "F.Cu")
		(net "GND")
	)
	(segment
		(start 88.725248 -287.288986)
		(end 88.724994 -287.28924)
		(width 0.254)
		(layer "F.Cu")
		(net "GND")
	)
	(segment
		(start 419.81374 -103.480108)
		(end 420.025068 -103.691436)
		(width 0.254)
		(layer "F.Cu")
		(net "GND")
	)
	(segment
		(start 307.782214 -242.3668)
		(end 308.887114 -242.3668)
		(width 0.381)
		(layer "F.Cu")
		(net "GND")
	)
	(segment
		(start 281.707082 -264.466578)
		(end 282.811982 -264.466578)
		(width 0.381)
		(layer "F.Cu")
		(net "GND")
	)
	(segment
		(start 260.180582 -314.616592)
		(end 259.075682 -314.616592)
		(width 0.381)
		(layer "F.Cu")
		(net "GND")
	)
	(segment
		(start 121.038112 -226.553268)
		(end 121.038112 -226.017582)
		(width 0.254)
		(layer "F.Cu")
		(net "GND")
	)
	(segment
		(start 274.163282 -239.81664)
		(end 275.268182 -239.81664)
		(width 0.381)
		(layer "F.Cu")
		(net "GND")
	)
	(segment
		(start 275.268182 -219.41663)
		(end 274.163282 -219.41663)
		(width 0.381)
		(layer "F.Cu")
		(net "GND")
	)
	(segment
		(start 278.711914 -300.166786)
		(end 279.816814 -300.166786)
		(width 0.381)
		(layer "F.Cu")
		(net "GND")
	)
	(segment
		(start 421.840914 -233.016806)
		(end 422.945814 -233.016806)
		(width 0.381)
		(layer "F.Cu")
		(net "GND")
	)
	(segment
		(start 211.619846 -216.016586)
		(end 212.724746 -216.016586)
		(width 0.381)
		(layer "F.Cu")
		(net "GND")
	)
	(segment
		(start 262.519414 -292.516814)
		(end 263.624314 -292.516814)
		(width 0.381)
		(layer "F.Cu")
		(net "GND")
	)
	(segment
		(start 166.357046 -240.666778)
		(end 167.461946 -240.666778)
		(width 0.381)
		(layer "F.Cu")
		(net "GND")
	)
	(segment
		(start 124.437648 -262.336534)
		(end 124.437648 -262.87222)
		(width 0.254)
		(layer "F.Cu")
		(net "GND")
	)
	(segment
		(start 406.753314 -199.01662)
		(end 407.858214 -199.01662)
		(width 0.381)
		(layer "F.Cu")
		(net "GND")
	)
	(segment
		(start 345.013534 -240.389156)
		(end 345.013534 -239.853216)
		(width 0.2032)
		(layer "F.Cu")
		(net "GND")
	)
	(segment
		(start 162.913314 -277.216616)
		(end 161.808414 -277.216616)
		(width 0.381)
		(layer "F.Cu")
		(net "GND")
	)
	(segment
		(start 311.666382 -310.366664)
		(end 312.987182 -310.366664)
		(width 0.381)
		(layer "F.Cu")
		(net "GND")
	)
	(segment
		(start 146.941286 -66.708528)
		(end 146.941286 -67.343528)
		(width 0.3556)
		(layer "F.Cu")
		(net "GND")
	)
	(segment
		(start 432.379882 -278.916638)
		(end 433.484782 -278.916638)
		(width 0.381)
		(layer "F.Cu")
		(net "GND")
	)
	(segment
		(start 278.711914 -238.966756)
		(end 279.816814 -238.966756)
		(width 0.381)
		(layer "F.Cu")
		(net "GND")
	)
	(segment
		(start 185.544714 -312.91657)
		(end 184.439814 -312.91657)
		(width 0.381)
		(layer "F.Cu")
		(net "GND")
	)
	(segment
		(start 296.578782 -235.566712)
		(end 297.899582 -235.566712)
		(width 0.381)
		(layer "F.Cu")
		(net "GND")
	)
	(segment
		(start 370.967762 -279.96388)
		(end 370.968016 -279.964134)
		(width 0.254)
		(layer "F.Cu")
		(net "GND")
	)
	(segment
		(start 413.192214 -227.066602)
		(end 414.297114 -227.066602)
		(width 0.381)
		(layer "F.Cu")
		(net "GND")
	)
	(segment
		(start 185.544714 -277.216616)
		(end 184.439814 -277.216616)
		(width 0.381)
		(layer "F.Cu")
		(net "GND")
	)
	(segment
		(start 101.302312 -216.78646)
		(end 101.302312 -216.250774)
		(width 0.254)
		(layer "F.Cu")
		(net "GND")
	)
	(segment
		(start 435.823614 -285.716726)
		(end 436.928514 -285.716726)
		(width 0.381)
		(layer "F.Cu")
		(net "GND")
	)
	(segment
		(start 345.013534 -217.600276)
		(end 345.013534 -217.064336)
		(width 0.2032)
		(layer "F.Cu")
		(net "GND")
	)
	(segment
		(start 204.076046 -263.616694)
		(end 205.180946 -263.616694)
		(width 0.381)
		(layer "F.Cu")
		(net "GND")
	)
	(segment
		(start 92.954094 -263.150604)
		(end 92.954094 -263.68629)
		(width 0.2032)
		(layer "F.Cu")
		(net "GND")
	)
	(segment
		(start 43.520614 -244.066568)
		(end 42.415714 -244.066568)
		(width 0.381)
		(layer "F.Cu")
		(net "GND")
	)
	(segment
		(start 444.472314 -225.36658)
		(end 443.367414 -225.36658)
		(width 0.381)
		(layer "F.Cu")
		(net "GND")
	)
	(segment
		(start 376.966734 -233.87812)
		(end 376.96648 -233.877866)
		(width 0.2032)
		(layer "F.Cu")
		(net "GND")
	)
	(segment
		(start 90.604848 -276.986492)
		(end 90.604848 -277.522432)
		(width 0.2032)
		(layer "F.Cu")
		(net "GND")
	)
	(segment
		(start 435.823614 -258.516628)
		(end 436.928514 -258.516628)
		(width 0.381)
		(layer "F.Cu")
		(net "GND")
	)
	(segment
		(start 300.238414 -248.31675)
		(end 301.343314 -248.31675)
		(width 0.381)
		(layer "F.Cu")
		(net "GND")
	)
	(segment
		(start 272.273014 -295.06672)
		(end 271.168114 -295.06672)
		(width 0.381)
		(layer "F.Cu")
		(net "GND")
	)
	(segment
		(start 118.328694 -282.683966)
		(end 118.328694 -283.219652)
		(width 0.254)
		(layer "F.Cu")
		(net "GND")
	)
	(segment
		(start 109.760512 -229.808786)
		(end 109.760766 -229.808532)
		(width 0.2032)
		(layer "F.Cu")
		(net "GND")
	)
	(segment
		(start 43.85691 -11.26998)
		(end 43.85691 -12.37488)
		(width 0.3556)
		(layer "F.Cu")
		(net "GND")
	)
	(segment
		(start 413.192214 -244.916706)
		(end 414.297114 -244.916706)
		(width 0.381)
		(layer "F.Cu")
		(net "GND")
	)
	(segment
		(start 425.940982 -196.466714)
		(end 427.045882 -196.466714)
		(width 0.381)
		(layer "F.Cu")
		(net "GND")
	)
	(segment
		(start 196.532246 -248.31675)
		(end 197.637146 -248.31675)
		(width 0.381)
		(layer "F.Cu")
		(net "GND")
	)
	(segment
		(start 419.809676 -291.666676)
		(end 418.397182 -291.666676)
		(width 0.381)
		(layer "F.Cu")
		(net "GND")
	)
	(segment
		(start 42.415714 -316.316614)
		(end 41.310814 -316.316614)
		(width 0.381)
		(layer "F.Cu")
		(net "GND")
	)
	(segment
		(start 334.785716 -275.35886)
		(end 334.315308 -275.08073)
		(width 0.2032)
		(layer "F.Cu")
		(net "GND")
	)
	(segment
		(start 194.759326 -36.433252)
		(end 194.759326 -35.595052)
		(width 0.3556)
		(layer "F.Cu")
		(net "GND")
	)
	(segment
		(start 459.559914 -296.766742)
		(end 460.664814 -296.766742)
		(width 0.381)
		(layer "F.Cu")
		(net "GND")
	)
	(segment
		(start 394.900658 -160.407858)
		(end 395.02334 -160.53054)
		(width 0.3556)
		(layer "F.Cu")
		(net "GND")
	)
	(segment
		(start 53.403246 -311.216802)
		(end 54.724046 -311.216802)
		(width 0.381)
		(layer "F.Cu")
		(net "GND")
	)
	(segment
		(start 263.624314 -309.51678)
		(end 264.729214 -309.51678)
		(width 0.381)
		(layer "F.Cu")
		(net "GND")
	)
	(segment
		(start 59.842146 -212.616796)
		(end 60.947046 -212.616796)
		(width 0.381)
		(layer "F.Cu")
		(net "GND")
	)
	(segment
		(start 370.21516 -407.020014)
		(end 370.952014 -407.020014)
		(width 0.3556)
		(layer "F.Cu")
		(net "GND")
	)
	(segment
		(start 304.338482 -299.316648)
		(end 305.443382 -299.316648)
		(width 0.381)
		(layer "F.Cu")
		(net "GND")
	)
	(segment
		(start 365.96955 -409.194)
		(end 365.3282 -409.194)
		(width 0.3556)
		(layer "F.Cu")
		(net "GND")
	)
	(segment
		(start 23.228046 -246.616728)
		(end 24.332946 -246.616728)
		(width 0.381)
		(layer "F.Cu")
		(net "GND")
	)
	(segment
		(start 373.317516 -257.45313)
		(end 373.317516 -257.98907)
		(width 0.2032)
		(layer "F.Cu")
		(net "GND")
	)
	(segment
		(start 436.928514 -283.166566)
		(end 438.033414 -283.166566)
		(width 0.381)
		(layer "F.Cu")
		(net "GND")
	)
	(segment
		(start 112.414812 -401.195286)
		(end 111.764826 -401.195286)
		(width 0.3556)
		(layer "F.Cu")
		(net "GND")
	)
	(segment
		(start 436.928514 -265.316716)
		(end 438.033414 -265.316716)
		(width 0.381)
		(layer "F.Cu")
		(net "GND")
	)
	(segment
		(start 14.579346 -279.766776)
		(end 15.684246 -279.766776)
		(width 0.381)
		(layer "F.Cu")
		(net "GND")
	)
	(segment
		(start 282.811982 -204.116686)
		(end 283.916882 -204.116686)
		(width 0.381)
		(layer "F.Cu")
		(net "GND")
	)
	(segment
		(start 45.859446 -201.56678)
		(end 46.964346 -201.56678)
		(width 0.381)
		(layer "F.Cu")
		(net "GND")
	)
	(segment
		(start 45.859446 -296.766742)
		(end 46.964346 -296.766742)
		(width 0.381)
		(layer "F.Cu")
		(net "GND")
	)
	(segment
		(start 105.061512 -223.297496)
		(end 105.061512 -222.76181)
		(width 0.254)
		(layer "F.Cu")
		(net "GND")
	)
	(segment
		(start 372.377716 -260.708902)
		(end 372.377716 -261.244588)
		(width 0.2032)
		(layer "F.Cu")
		(net "GND")
	)
	(segment
		(start 45.859446 -265.316716)
		(end 46.964346 -265.316716)
		(width 0.381)
		(layer "F.Cu")
		(net "GND")
	)
	(segment
		(start 441.028582 -277.216616)
		(end 442.133482 -277.216616)
		(width 0.381)
		(layer "F.Cu")
		(net "GND")
	)
	(segment
		(start 328.194162 -54.003702)
		(end 328.194162 -54.902608)
		(width 0.2032)
		(layer "F.Cu")
		(net "GND")
	)
	(segment
		(start 120.208548 -282.68422)
		(end 120.208548 -283.219906)
		(width 0.254)
		(layer "F.Cu")
		(net "GND")
	)
	(segment
		(start 337.495134 -228.459284)
		(end 337.49488 -228.45903)
		(width 0.2032)
		(layer "F.Cu")
		(net "GND")
	)
	(segment
		(start 336.55508 -235.505752)
		(end 336.55508 -234.970066)
		(width 0.2032)
		(layer "F.Cu")
		(net "GND")
	)
	(segment
		(start 419.502082 -226.216718)
		(end 418.397182 -226.216718)
		(width 0.381)
		(layer "F.Cu")
		(net "GND")
	)
	(segment
		(start 134.195566 -215.158574)
		(end 134.195566 -214.546434)
		(width 0.254)
		(layer "F.Cu")
		(net "GND")
	)
	(segment
		(start 371.437916 -272.103342)
		(end 371.437662 -272.639282)
		(width 0.2032)
		(layer "F.Cu")
		(net "GND")
	)
	(segment
		(start 157.708346 -306.116736)
		(end 158.813246 -306.116736)
		(width 0.381)
		(layer "F.Cu")
		(net "GND")
	)
	(segment
		(start 162.913314 -247.466612)
		(end 161.808414 -247.466612)
		(width 0.381)
		(layer "F.Cu")
		(net "GND")
	)
	(segment
		(start 219.67952 -48.53432)
		(end 219.006928 -48.53432)
		(width 0.3556)
		(layer "F.Cu")
		(net "GND")
	)
	(segment
		(start 304.338482 -277.216616)
		(end 305.443382 -277.216616)
		(width 0.381)
		(layer "F.Cu")
		(net "GND")
	)
	(segment
		(start 132.895594 -280.242518)
		(end 132.895594 -280.778204)
		(width 0.254)
		(layer "F.Cu")
		(net "GND")
	)
	(segment
		(start 125.377448 -267.219938)
		(end 125.377194 -267.755878)
		(width 0.2032)
		(layer "F.Cu")
		(net "GND")
	)
	(segment
		(start 344.183716 -278.614378)
		(end 344.183716 -279.150064)
		(width 0.254)
		(layer "F.Cu")
		(net "GND")
	)
	(segment
		(start 52.298346 -270.416782)
		(end 53.403246 -270.416782)
		(width 0.381)
		(layer "F.Cu")
		(net "GND")
	)
	(segment
		(start 157.708346 -251.716794)
		(end 158.813246 -251.716794)
		(width 0.381)
		(layer "F.Cu")
		(net "GND")
	)
	(segment
		(start 305.443382 -249.166634)
		(end 306.548282 -249.166634)
		(width 0.381)
		(layer "F.Cu")
		(net "GND")
	)
	(segment
		(start 111.640112 -215.158574)
		(end 111.640112 -214.546688)
		(width 0.254)
		(layer "F.Cu")
		(net "GND")
	)
	(segment
		(start 421.840914 -292.516814)
		(end 420.736014 -292.516814)
		(width 0.381)
		(layer "F.Cu")
		(net "GND")
	)
	(segment
		(start 180.339746 -206.666592)
		(end 181.444646 -206.666592)
		(width 0.381)
		(layer "F.Cu")
		(net "GND")
	)
	(segment
		(start 190.093346 -220.266768)
		(end 188.988446 -220.266768)
		(width 0.381)
		(layer "F.Cu")
		(net "GND")
	)
	(segment
		(start 199.527414 -198.166736)
		(end 200.632314 -198.166736)
		(width 0.381)
		(layer "F.Cu")
		(net "GND")
	)
	(segment
		(start 101.772466 -245.27256)
		(end 101.772212 -245.272306)
		(width 0.2032)
		(layer "F.Cu")
		(net "GND")
	)
	(segment
		(start 93.195394 -338.619338)
		(end 93.195394 -338.796884)
		(width 0.381)
		(layer "F.Cu")
		(net "GND")
	)
	(segment
		(start 385.424934 -232.250488)
		(end 384.485134 -231.714548)
		(width 0.254)
		(layer "F.Cu")
		(net "GND")
	)
	(segment
		(start 463.659982 -269.566644)
		(end 464.764882 -269.566644)
		(width 0.381)
		(layer "F.Cu")
		(net "GND")
	)
	(segment
		(start 305.443382 -235.566712)
		(end 306.751482 -235.566712)
		(width 0.381)
		(layer "F.Cu")
		(net "GND")
	)
	(segment
		(start 137.594594 -257.45313)
		(end 137.594594 -257.988816)
		(width 0.254)
		(layer "F.Cu")
		(net "GND")
	)
	(segment
		(start 126.786894 -277.800562)
		(end 126.787148 -278.336502)
		(width 0.2032)
		(layer "F.Cu")
		(net "GND")
	)
	(segment
		(start 294.904414 -306.116736)
		(end 293.799514 -306.116736)
		(width 0.381)
		(layer "F.Cu")
		(net "GND")
	)
	(segment
		(start 44.569634 -107.031282)
		(end 45.179234 -107.031282)
		(width 0.3556)
		(layer "F.Cu")
		(net "GND")
	)
	(segment
		(start 30.771846 -248.31675)
		(end 31.876746 -248.31675)
		(width 0.381)
		(layer "F.Cu")
		(net "GND")
	)
	(segment
		(start 293.799514 -290.816792)
		(end 292.694614 -290.816792)
		(width 0.381)
		(layer "F.Cu")
		(net "GND")
	)
	(segment
		(start 430.643284 -178.801522)
		(end 429.992282 -178.801522)
		(width 0.381)
		(layer "F.Cu")
		(net "GND")
	)
	(segment
		(start 307.782214 -304.416714)
		(end 308.887114 -304.416714)
		(width 0.381)
		(layer "F.Cu")
		(net "GND")
	)
	(segment
		(start 432.379882 -269.566644)
		(end 433.484782 -269.566644)
		(width 0.381)
		(layer "F.Cu")
		(net "GND")
	)
	(segment
		(start 337.134962 -255.011682)
		(end 337.135216 -255.547622)
		(width 0.2032)
		(layer "F.Cu")
		(net "GND")
	)
	(segment
		(start 414.297114 -273.816572)
		(end 415.605214 -273.816572)
		(width 0.381)
		(layer "F.Cu")
		(net "GND")
	)
	(segment
		(start 294.904414 -195.616576)
		(end 293.799514 -195.616576)
		(width 0.381)
		(layer "F.Cu")
		(net "GND")
	)
	(segment
		(start 335.138268 -56.438546)
		(end 335.67878 -56.438546)
		(width 0.2032)
		(layer "F.Cu")
		(net "GND")
	)
	(segment
		(start 352.641916 -285.125414)
		(end 352.641916 -285.6611)
		(width 0.254)
		(layer "F.Cu")
		(net "GND")
	)
	(segment
		(start 297.899582 -235.566712)
		(end 299.004482 -235.566712)
		(width 0.381)
		(layer "F.Cu")
		(net "GND")
	)
	(segment
		(start 457.221082 -222.816674)
		(end 456.116182 -222.816674)
		(width 0.381)
		(layer "F.Cu")
		(net "GND")
	)
	(segment
		(start 418.397182 -250.866656)
		(end 417.292282 -250.866656)
		(width 0.381)
		(layer "F.Cu")
		(net "GND")
	)
	(segment
		(start 380.835916 -281.869896)
		(end 380.835662 -282.405836)
		(width 0.254)
		(layer "F.Cu")
		(net "GND")
	)
	(segment
		(start 29.666946 -225.36658)
		(end 30.771846 -225.36658)
		(width 0.381)
		(layer "F.Cu")
		(net "GND")
	)
	(segment
		(start 380.835916 -265.592306)
		(end 380.835916 -266.127992)
		(width 0.254)
		(layer "F.Cu")
		(net "GND")
	)
	(segment
		(start 173.900846 -306.116736)
		(end 175.005746 -306.116736)
		(width 0.381)
		(layer "F.Cu")
		(net "GND")
	)
	(segment
		(start 411.958282 -289.966654)
		(end 410.853382 -289.966654)
		(width 0.381)
		(layer "F.Cu")
		(net "GND")
	)
	(segment
		(start 335.725262 -275.35886)
		(end 335.255108 -275.080984)
		(width 0.254)
		(layer "F.Cu")
		(net "GND")
	)
	(segment
		(start 132.425694 -257.175254)
		(end 132.425694 -256.639314)
		(width 0.2032)
		(layer "F.Cu")
		(net "GND")
	)
	(segment
		(start 405.648414 -292.516814)
		(end 406.753314 -292.516814)
		(width 0.381)
		(layer "F.Cu")
		(net "GND")
	)
	(segment
		(start 165.252146 -210.916774)
		(end 166.357046 -210.916774)
		(width 0.381)
		(layer "F.Cu")
		(net "GND")
	)
	(segment
		(start 370.388134 -242.017042)
		(end 370.388134 -241.481102)
		(width 0.254)
		(layer "F.Cu")
		(net "GND")
	)
	(segment
		(start 45.859446 -317.166752)
		(end 44.754546 -317.166752)
		(width 0.381)
		(layer "F.Cu")
		(net "GND")
	)
	(segment
		(start 121.148348 -281.591766)
		(end 121.148348 -281.59202)
		(width 0.254)
		(layer "F.Cu")
		(net "GND")
	)
	(segment
		(start 334.785716 -276.986492)
		(end 335.241646 -277.244302)
		(width 0.254)
		(layer "F.Cu")
		(net "GND")
	)
	(segment
		(start 169.27195 -358.535986)
		(end 169.27195 -359.2068)
		(width 0.3556)
		(layer "F.Cu")
		(net "GND")
	)
	(segment
		(start 129.606294 -263.150604)
		(end 129.606294 -263.686544)
		(width 0.2032)
		(layer "F.Cu")
		(net "GND")
	)
	(segment
		(start 173.900846 -260.21665)
		(end 172.795946 -260.21665)
		(width 0.381)
		(layer "F.Cu")
		(net "GND")
	)
	(segment
		(start 53.07457 -145.089626)
		(end 53.07457 -145.441924)
		(width 0.2032)
		(layer "F.Cu")
		(net "GND")
	)
	(segment
		(start 135.605266 -226.831144)
		(end 135.605266 -227.367084)
		(width 0.254)
		(layer "F.Cu")
		(net "GND")
	)
	(segment
		(start 23.228046 -304.416714)
		(end 24.332946 -304.416714)
		(width 0.381)
		(layer "F.Cu")
		(net "GND")
	)
	(segment
		(start 173.900846 -283.166566)
		(end 175.005746 -283.166566)
		(width 0.381)
		(layer "F.Cu")
		(net "GND")
	)
	(segment
		(start 435.823614 -246.616728)
		(end 436.928514 -246.616728)
		(width 0.381)
		(layer "F.Cu")
		(net "GND")
	)
	(segment
		(start 356.76078 -216.250774)
		(end 356.761034 -216.25052)
		(width 0.254)
		(layer "F.Cu")
		(net "GND")
	)
	(segment
		(start 110.340648 -255.825498)
		(end 110.340648 -256.361438)
		(width 0.254)
		(layer "F.Cu")
		(net "GND")
	)
	(segment
		(start 39.420546 -279.766776)
		(end 38.315646 -279.766776)
		(width 0.381)
		(layer "F.Cu")
		(net "GND")
	)
	(segment
		(start 93.783912 -222.76181)
		(end 93.784166 -222.761556)
		(width 0.254)
		(layer "F.Cu")
		(net "GND")
	)
	(segment
		(start 275.268182 -198.166736)
		(end 274.163282 -198.166736)
		(width 0.381)
		(layer "F.Cu")
		(net "GND")
	)
	(segment
		(start 337.604608 -279.14981)
		(end 337.604862 -279.150064)
		(width 0.2032)
		(layer "F.Cu")
		(net "GND")
	)
	(segment
		(start 375.666762 -268.033754)
		(end 375.667016 -268.569694)
		(width 0.2032)
		(layer "F.Cu")
		(net "GND")
	)
	(segment
		(start 178.000914 -213.46668)
		(end 176.896014 -213.46668)
		(width 0.381)
		(layer "F.Cu")
		(net "GND")
	)
	(segment
		(start 193.088514 -224.516696)
		(end 191.983614 -224.516696)
		(width 0.381)
		(layer "F.Cu")
		(net "GND")
	)
	(segment
		(start 341.833962 -255.547368)
		(end 341.834216 -255.547622)
		(width 0.2032)
		(layer "F.Cu")
		(net "GND")
	)
	(segment
		(start 214.4268 -107.01655)
		(end 214.4268 -106.3752)
		(width 0.3556)
		(layer "F.Cu")
		(net "GND")
	)
	(segment
		(start 125.847348 -281.056334)
		(end 125.847348 -281.59202)
		(width 0.254)
		(layer "F.Cu")
		(net "GND")
	)
	(segment
		(start 34.871914 -258.516628)
		(end 35.976814 -258.516628)
		(width 0.381)
		(layer "F.Cu")
		(net "GND")
	)
	(segment
		(start 98.482912 -220.041978)
		(end 98.483166 -220.041724)
		(width 0.254)
		(layer "F.Cu")
		(net "GND")
	)
	(segment
		(start 406.753314 -306.116736)
		(end 407.858214 -306.116736)
		(width 0.381)
		(layer "F.Cu")
		(net "GND")
	)
	(segment
		(start 371.327934 -217.600276)
		(end 371.327934 -217.064336)
		(width 0.254)
		(layer "F.Cu")
		(net "GND")
	)
	(segment
		(start 98.013266 -238.761524)
		(end 98.013266 -238.225584)
		(width 0.2032)
		(layer "F.Cu")
		(net "GND")
	)
	(segment
		(start 49.959514 -299.316648)
		(end 51.064414 -299.316648)
		(width 0.381)
		(layer "F.Cu")
		(net "GND")
	)
	(segment
		(start 304.338482 -262.76681)
		(end 305.443382 -262.76681)
		(width 0.381)
		(layer "F.Cu")
		(net "GND")
	)
	(segment
		(start 285.150814 -268.71676)
		(end 286.255714 -268.71676)
		(width 0.381)
		(layer "F.Cu")
		(net "GND")
	)
	(segment
		(start 305.443382 -301.01667)
		(end 306.548282 -301.01667)
		(width 0.381)
		(layer "F.Cu")
		(net "GND")
	)
	(segment
		(start 349.822516 -275.35886)
		(end 349.822516 -275.894546)
		(width 0.254)
		(layer "F.Cu")
		(net "GND")
	)
	(segment
		(start 57.503314 -202.416664)
		(end 58.608214 -202.416664)
		(width 0.381)
		(layer "F.Cu")
		(net "GND")
	)
	(segment
		(start 421.840914 -225.36658)
		(end 422.945814 -225.36658)
		(width 0.381)
		(layer "F.Cu")
		(net "GND")
	)
	(segment
		(start 341.282274 -338.472272)
		(end 341.135208 -338.619338)
		(width 0.381)
		(layer "F.Cu")
		(net "GND")
	)
	(segment
		(start 124.797312 -226.553268)
		(end 124.797312 -226.017582)
		(width 0.254)
		(layer "F.Cu")
		(net "GND")
	)
	(segment
		(start 372.267734 -245.27256)
		(end 372.26748 -245.272306)
		(width 0.2032)
		(layer "F.Cu")
		(net "GND")
	)
	(segment
		(start 60.947046 -279.766776)
		(end 62.051946 -279.766776)
		(width 0.381)
		(layer "F.Cu")
		(net "GND")
	)
	(segment
		(start 421.840914 -267.016738)
		(end 422.945814 -267.016738)
		(width 0.4064)
		(layer "F.Cu")
		(net "GND")
	)
	(segment
		(start 70.861936 -7.215124)
		(end 70.861936 -8.320024)
		(width 0.3556)
		(layer "F.Cu")
		(net "GND")
	)
	(segment
		(start 370.967762 -276.172676)
		(end 370.968016 -276.708616)
		(width 0.2032)
		(layer "F.Cu")
		(net "GND")
	)
	(segment
		(start 371.437916 -257.45313)
		(end 371.437662 -257.98907)
		(width 0.2032)
		(layer "F.Cu")
		(net "GND")
	)
	(segment
		(start 8.140446 -317.166752)
		(end 9.245346 -317.166752)
		(width 0.381)
		(layer "F.Cu")
		(net "GND")
	)
	(segment
		(start 263.624314 -289.11677)
		(end 264.729214 -289.11677)
		(width 0.381)
		(layer "F.Cu")
		(net "GND")
	)
	(segment
		(start 137.484866 -228.99497)
		(end 136.545066 -228.45903)
		(width 0.254)
		(layer "F.Cu")
		(net "GND")
	)
	(segment
		(start 448.572382 -258.516628)
		(end 447.467482 -258.516628)
		(width 0.381)
		(layer "F.Cu")
		(net "GND")
	)
	(segment
		(start 126.676912 -223.297496)
		(end 126.676912 -222.76181)
		(width 0.254)
		(layer "F.Cu")
		(net "GND")
	)
	(segment
		(start 363.339634 -220.041724)
		(end 363.339634 -219.506038)
		(width 0.254)
		(layer "F.Cu")
		(net "GND")
	)
	(segment
		(start 435.823614 -300.166786)
		(end 436.928514 -300.166786)
		(width 0.381)
		(layer "F.Cu")
		(net "GND")
	)
	(segment
		(start 417.71189 -105.207308)
		(end 417.10229 -105.207308)
		(width 0.3556)
		(layer "F.Cu")
		(net "GND")
	)
	(segment
		(start 409.270962 -360.722926)
		(end 406.524714 -360.722926)
		(width 0.381)
		(layer "F.Cu")
		(net "GND")
	)
	(segment
		(start 262.519414 -236.416596)
		(end 263.624314 -236.416596)
		(width 0.381)
		(layer "F.Cu")
		(net "GND")
	)
	(segment
		(start 88.255094 -271.289272)
		(end 88.255094 -271.825212)
		(width 0.2032)
		(layer "F.Cu")
		(net "GND")
	)
	(segment
		(start 266.619482 -198.166736)
		(end 267.724382 -198.166736)
		(width 0.381)
		(layer "F.Cu")
		(net "GND")
	)
	(segment
		(start 334.315562 -271.289272)
		(end 335.255362 -271.825212)
		(width 0.2032)
		(layer "F.Cu")
		(net "GND")
	)
	(segment
		(start 200.632314 -250.866656)
		(end 201.737214 -250.866656)
		(width 0.381)
		(layer "F.Cu")
		(net "GND")
	)
	(segment
		(start 133.255512 -220.041978)
		(end 133.255512 -219.506292)
		(width 0.254)
		(layer "F.Cu")
		(net "GND")
	)
	(segment
		(start 448.572382 -271.266666)
		(end 447.467482 -271.266666)
		(width 0.381)
		(layer "F.Cu")
		(net "GND")
	)
	(segment
		(start 448.572382 -249.166634)
		(end 447.467482 -249.166634)
		(width 0.381)
		(layer "F.Cu")
		(net "GND")
	)
	(segment
		(start 85.435694 -259.894832)
		(end 85.905594 -259.616956)
		(width 0.254)
		(layer "F.Cu")
		(net "GND")
	)
	(segment
		(start 358.280716 -272.103342)
		(end 358.280716 -272.639028)
		(width 0.254)
		(layer "F.Cu")
		(net "GND")
	)
	(segment
		(start 200.632314 -286.56661)
		(end 201.737214 -286.56661)
		(width 0.381)
		(layer "F.Cu")
		(net "GND")
	)
	(segment
		(start 110.230666 -250.155964)
		(end 110.23092 -250.15571)
		(width 0.254)
		(layer "F.Cu")
		(net "GND")
	)
	(segment
		(start 276.373082 -261.066788)
		(end 275.268182 -261.066788)
		(width 0.381)
		(layer "F.Cu")
		(net "GND")
	)
	(segment
		(start 410.853382 -271.266666)
		(end 409.697682 -271.266666)
		(width 0.381)
		(layer "F.Cu")
		(net "GND")
	)
	(segment
		(start 422.074594 -153.510742)
		(end 421.396414 -153.510742)
		(width 0.254)
		(layer "F.Cu")
		(net "GND")
	)
	(segment
		(start 453.121014 -281.466798)
		(end 452.016114 -281.466798)
		(width 0.381)
		(layer "F.Cu")
		(net "GND")
	)
	(segment
		(start 96.243394 -263.964674)
		(end 96.243394 -264.50036)
		(width 0.254)
		(layer "F.Cu")
		(net "GND")
	)
	(segment
		(start 135.605266 -241.481102)
		(end 135.605266 -242.017042)
		(width 0.254)
		(layer "F.Cu")
		(net "GND")
	)
	(segment
		(start 384.595116 -272.103342)
		(end 384.139948 -271.834102)
		(width 0.254)
		(layer "F.Cu")
		(net "GND")
	)
	(segment
		(start 358.280716 -287.288986)
		(end 358.280462 -287.28924)
		(width 0.254)
		(layer "F.Cu")
		(net "GND")
	)
	(segment
		(start 293.799514 -301.866808)
		(end 292.694614 -301.866808)
		(width 0.381)
		(layer "F.Cu")
		(net "GND")
	)
	(segment
		(start 119.94134 -411.131004)
		(end 119.23903 -411.131004)
		(width 0.3556)
		(layer "F.Cu")
		(net "GND")
	)
	(segment
		(start 448.572382 -233.86669)
		(end 447.467482 -233.86669)
		(width 0.381)
		(layer "F.Cu")
		(net "GND")
	)
	(segment
		(start 347.363034 -246.086376)
		(end 347.363034 -245.55069)
		(width 0.2032)
		(layer "F.Cu")
		(net "GND")
	)
	(segment
		(start 157.479746 -272.116804)
		(end 158.813246 -272.116804)
		(width 0.381)
		(layer "F.Cu")
		(net "GND")
	)
	(segment
		(start 286.255714 -290.816792)
		(end 287.360614 -290.816792)
		(width 0.381)
		(layer "F.Cu")
		(net "GND")
	)
	(segment
		(start 12.240514 -266.1666)
		(end 13.345414 -266.1666)
		(width 0.381)
		(layer "F.Cu")
		(net "GND")
	)
	(segment
		(start 170.155616 -121.775474)
		(end 169.755566 -122.175524)
		(width 0.3556)
		(layer "F.Cu")
		(net "GND")
	)
	(segment
		(start 440.211972 -31.781242)
		(end 441.353194 -30.64002)
		(width 0.254)
		(layer "F.Cu")
		(net "GND")
	)
	(segment
		(start 123.027694 -268.033754)
		(end 123.027694 -268.569694)
		(width 0.254)
		(layer "F.Cu")
		(net "GND")
	)
	(segment
		(start 68.672456 -29.29001)
		(end 68.672456 -30.07741)
		(width 0.17272)
		(layer "F.Cu")
		(net "GND")
	)
	(segment
		(start 346.893134 -224.111566)
		(end 346.893134 -223.575626)
		(width 0.2032)
		(layer "F.Cu")
		(net "GND")
	)
	(segment
		(start 414.297114 -265.316716)
		(end 415.402014 -265.316716)
		(width 0.381)
		(layer "F.Cu")
		(net "GND")
	)
	(segment
		(start 202.971146 -315.46673)
		(end 204.076046 -315.46673)
		(width 0.381)
		(layer "F.Cu")
		(net "GND")
	)
	(segment
		(start 115.82908 -400.815048)
		(end 115.82908 -401.424648)
		(width 0.3556)
		(layer "F.Cu")
		(net "GND")
	)
	(segment
		(start 414.297114 -203.266802)
		(end 415.402014 -203.266802)
		(width 0.381)
		(layer "F.Cu")
		(net "GND")
	)
	(segment
		(start 131.956048 -280.242264)
		(end 131.955794 -280.778204)
		(width 0.2032)
		(layer "F.Cu")
		(net "GND")
	)
	(segment
		(start 459.559914 -315.46673)
		(end 460.664814 -315.46673)
		(width 0.381)
		(layer "F.Cu")
		(net "GND")
	)
	(segment
		(start 340.78418 -236.319822)
		(end 340.784434 -236.319568)
		(width 0.2032)
		(layer "F.Cu")
		(net "GND")
	)
	(segment
		(start 151.73325 -36.341558)
		(end 152.09393 -36.341558)
		(width 0.3556)
		(layer "F.Cu")
		(net "GND")
	)
	(segment
		(start 43.520614 -221.116652)
		(end 42.415714 -221.116652)
		(width 0.381)
		(layer "F.Cu")
		(net "GND")
	)
	(segment
		(start 107.051094 -277.800562)
		(end 107.051094 -278.336248)
		(width 0.254)
		(layer "F.Cu")
		(net "GND")
	)
	(segment
		(start 120.568466 -232.250488)
		(end 120.568212 -232.250234)
		(width 0.2032)
		(layer "F.Cu")
		(net "GND")
	)
	(segment
		(start 26.223214 -211.766658)
		(end 27.328114 -211.766658)
		(width 0.381)
		(layer "F.Cu")
		(net "GND")
	)
	(segment
		(start 98.482912 -226.553268)
		(end 98.482912 -226.017582)
		(width 0.254)
		(layer "F.Cu")
		(net "GND")
	)
	(segment
		(start 103.181912 -226.553268)
		(end 103.181912 -226.017582)
		(width 0.254)
		(layer "F.Cu")
		(net "GND")
	)
	(segment
		(start 194.193414 -238.116618)
		(end 193.088514 -238.116618)
		(width 0.381)
		(layer "F.Cu")
		(net "GND")
	)
	(segment
		(start 214.615014 -310.366664)
		(end 215.719914 -310.366664)
		(width 0.381)
		(layer "F.Cu")
		(net "GND")
	)
	(segment
		(start 114.68608 -122.532648)
		(end 114.68608 -123.148598)
		(width 0.3556)
		(layer "F.Cu")
		(net "GND")
	)
	(segment
		(start 366.15878 -233.064304)
		(end 366.15878 -232.528618)
		(width 0.2032)
		(layer "F.Cu")
		(net "GND")
	)
	(segment
		(start 54.878732 -144.694148)
		(end 55.6387 -144.694148)
		(width 0.2032)
		(layer "F.Cu")
		(net "GND")
	)
	(segment
		(start 112.092232 -406.439116)
		(end 112.092232 -407.074116)
		(width 0.3556)
		(layer "F.Cu")
		(net "GND")
	)
	(segment
		(start 296.794682 -271.266666)
		(end 297.899582 -271.266666)
		(width 0.381)
		(layer "F.Cu")
		(net "GND")
	)
	(segment
		(start 165.252146 -221.96679)
		(end 166.357046 -221.96679)
		(width 0.381)
		(layer "F.Cu")
		(net "GND")
	)
	(segment
		(start 131.956048 -262.336534)
		(end 131.956048 -262.872474)
		(width 0.2032)
		(layer "F.Cu")
		(net "GND")
	)
	(segment
		(start 115.869212 -230.622348)
		(end 115.869212 -230.086662)
		(width 0.254)
		(layer "F.Cu")
		(net "GND")
	)
	(segment
		(start 357.340662 -272.103342)
		(end 357.340662 -272.639282)
		(width 0.2032)
		(layer "F.Cu")
		(net "GND")
	)
	(segment
		(start 135.135112 -242.295172)
		(end 135.135366 -242.294918)
		(width 0.2032)
		(layer "F.Cu")
		(net "GND")
	)
	(segment
		(start 100.832666 -233.87812)
		(end 100.832412 -233.877866)
		(width 0.2032)
		(layer "F.Cu")
		(net "GND")
	)
	(segment
		(start 86.375494 -264.778236)
		(end 86.845394 -264.50036)
		(width 0.254)
		(layer "F.Cu")
		(net "GND")
	)
	(segment
		(start 19.784314 -228.766624)
		(end 20.889214 -228.766624)
		(width 0.381)
		(layer "F.Cu")
		(net "GND")
	)
	(segment
		(start 294.904414 -217.716608)
		(end 293.799514 -217.716608)
		(width 0.381)
		(layer "F.Cu")
		(net "GND")
	)
	(segment
		(start 332.796134 -228.99497)
		(end 332.326234 -229.272846)
		(width 0.2032)
		(layer "F.Cu")
		(net "GND")
	)
	(segment
		(start 239.61852 -246.530368)
		(end 240.50371 -247.415558)
		(width 0.3556)
		(layer "F.Cu")
		(net "GND")
	)
	(segment
		(start 308.887114 -309.51678)
		(end 309.992014 -309.51678)
		(width 0.381)
		(layer "F.Cu")
		(net "GND")
	)
	(segment
		(start 441.028582 -261.066788)
		(end 442.133482 -261.066788)
		(width 0.381)
		(layer "F.Cu")
		(net "GND")
	)
	(segment
		(start 359.58018 -216.78646)
		(end 359.58018 -216.250774)
		(width 0.254)
		(layer "F.Cu")
		(net "GND")
	)
	(segment
		(start 126.207266 -237.133892)
		(end 126.207012 -237.133638)
		(width 0.254)
		(layer "F.Cu")
		(net "GND")
	)
	(segment
		(start 334.315562 -255.011682)
		(end 334.785462 -254.733552)
		(width 0.254)
		(layer "F.Cu")
		(net "GND")
	)
	(segment
		(start 307.782214 -307.816758)
		(end 308.887114 -307.816758)
		(width 0.381)
		(layer "F.Cu")
		(net "GND")
	)
	(segment
		(start 337.604862 -286.7533)
		(end 337.604862 -287.28924)
		(width 0.254)
		(layer "F.Cu")
		(net "GND")
	)
	(segment
		(start 34.871914 -232.166668)
		(end 35.976814 -232.166668)
		(width 0.381)
		(layer "F.Cu")
		(net "GND")
	)
	(segment
		(start 88.615266 -235.506006)
		(end 88.615012 -235.505752)
		(width 0.2032)
		(layer "F.Cu")
		(net "GND")
	)
	(segment
		(start 463.659982 -278.916638)
		(end 462.555082 -278.916638)
		(width 0.381)
		(layer "F.Cu")
		(net "GND")
	)
	(segment
		(start 256.080514 -317.166752)
		(end 257.185414 -317.166752)
		(width 0.381)
		(layer "F.Cu")
		(net "GND")
	)
	(segment
		(start 449.677282 -222.816674)
		(end 448.572382 -222.816674)
		(width 0.381)
		(layer "F.Cu")
		(net "GND")
	)
	(segment
		(start 63.942214 -202.416664)
		(end 65.047114 -202.416664)
		(width 0.381)
		(layer "F.Cu")
		(net "GND")
	)
	(segment
		(start 463.659982 -299.316648)
		(end 462.555082 -299.316648)
		(width 0.381)
		(layer "F.Cu")
		(net "GND")
	)
	(segment
		(start 44.754546 -283.166566)
		(end 45.859446 -283.166566)
		(width 0.381)
		(layer "F.Cu")
		(net "GND")
	)
	(segment
		(start 344.653362 -281.05608)
		(end 344.653362 -281.591766)
		(width 0.254)
		(layer "F.Cu")
		(net "GND")
	)
	(segment
		(start 53.403246 -197.316598)
		(end 54.508146 -197.316598)
		(width 0.381)
		(layer "F.Cu")
		(net "GND")
	)
	(segment
		(start 92.844366 -249.341894)
		(end 92.844366 -248.806208)
		(width 0.2032)
		(layer "F.Cu")
		(net "GND")
	)
	(segment
		(start 42.29862 -102.07879)
		(end 43.47972 -102.07879)
		(width 0.3556)
		(layer "F.Cu")
		(net "GND")
	)
	(segment
		(start 204.076046 -195.616576)
		(end 205.180946 -195.616576)
		(width 0.381)
		(layer "F.Cu")
		(net "GND")
	)
	(segment
		(start 90.494866 -225.739198)
		(end 90.494866 -225.203512)
		(width 0.2032)
		(layer "F.Cu")
		(net "GND")
	)
	(segment
		(start 89.554812 -246.900192)
		(end 89.554812 -246.364506)
		(width 0.2032)
		(layer "F.Cu")
		(net "GND")
	)
	(segment
		(start 100.832412 -228.994716)
		(end 100.832412 -228.45903)
		(width 0.2032)
		(layer "F.Cu")
		(net "GND")
	)
	(segment
		(start 340.78418 -234.156504)
		(end 340.784434 -234.15625)
		(width 0.254)
		(layer "F.Cu")
		(net "GND")
	)
	(segment
		(start 124.437648 -268.84757)
		(end 124.437394 -269.38351)
		(width 0.254)
		(layer "F.Cu")
		(net "GND")
	)
	(segment
		(start 378.956316 -265.592306)
		(end 378.956316 -266.127992)
		(width 0.254)
		(layer "F.Cu")
		(net "GND")
	)
	(segment
		(start 407.446988 -11.26998)
		(end 407.446988 -10.16508)
		(width 0.3556)
		(layer "F.Cu")
		(net "GND")
	)
	(segment
		(start 197.637146 -290.816792)
		(end 196.532246 -290.816792)
		(width 0.381)
		(layer "F.Cu")
		(net "GND")
	)
	(segment
		(start 405.648414 -233.016806)
		(end 406.753314 -233.016806)
		(width 0.381)
		(layer "F.Cu")
		(net "GND")
	)
	(segment
		(start 463.659982 -303.566576)
		(end 462.555082 -303.566576)
		(width 0.381)
		(layer "F.Cu")
		(net "GND")
	)
	(segment
		(start 182.549546 -306.116736)
		(end 181.444646 -306.116736)
		(width 0.381)
		(layer "F.Cu")
		(net "GND")
	)
	(segment
		(start 457.221082 -226.216718)
		(end 456.116182 -226.216718)
		(width 0.381)
		(layer "F.Cu")
		(net "GND")
	)
	(segment
		(start 58.608214 -258.516628)
		(end 57.503314 -258.516628)
		(width 0.381)
		(layer "F.Cu")
		(net "GND")
	)
	(segment
		(start 42.415714 -244.066568)
		(end 41.310814 -244.066568)
		(width 0.381)
		(layer "F.Cu")
		(net "GND")
	)
	(segment
		(start 428.279814 -289.11677)
		(end 429.384714 -289.11677)
		(width 0.381)
		(layer "F.Cu")
		(net "GND")
	)
	(segment
		(start 335.899252 -58.43524)
		(end 335.790794 -58.889392)
		(width 0.2032)
		(layer "F.Cu")
		(net "GND")
	)
	(segment
		(start 111.13008 -122.532648)
		(end 111.13008 -123.148598)
		(width 0.3556)
		(layer "F.Cu")
		(net "GND")
	)
	(segment
		(start 382.618488 -342.964008)
		(end 382.618488 -342.5317)
		(width 0.2032)
		(layer "F.Cu")
		(net "GND")
	)
	(segment
		(start 410.853382 -244.066568)
		(end 409.748482 -244.066568)
		(width 0.381)
		(layer "F.Cu")
		(net "GND")
	)
	(segment
		(start 418.36594 -109.671358)
		(end 418.36594 -110.280958)
		(width 0.3556)
		(layer "F.Cu")
		(net "GND")
	)
	(segment
		(start 196.532246 -238.966756)
		(end 197.637146 -238.966756)
		(width 0.381)
		(layer "F.Cu")
		(net "GND")
	)
	(segment
		(start 93.314266 -220.855794)
		(end 93.314266 -220.319854)
		(width 0.2032)
		(layer "F.Cu")
		(net "GND")
	)
	(segment
		(start 194.193414 -219.41663)
		(end 193.088514 -219.41663)
		(width 0.381)
		(layer "F.Cu")
		(net "GND")
	)
	(segment
		(start 376.966734 -238.761524)
		(end 376.96648 -238.76127)
		(width 0.2032)
		(layer "F.Cu")
		(net "GND")
	)
	(segment
		(start 414.297114 -208.366614)
		(end 415.630614 -208.366614)
		(width 0.381)
		(layer "F.Cu")
		(net "GND")
	)
	(segment
		(start 355.82098 -226.017582)
		(end 355.821234 -226.017328)
		(width 0.254)
		(layer "F.Cu")
		(net "GND")
	)
	(segment
		(start 113.519712 -239.57534)
		(end 113.519712 -239.039908)
		(width 0.254)
		(layer "F.Cu")
		(net "GND")
	)
	(segment
		(start 60.947046 -300.166786)
		(end 62.051946 -300.166786)
		(width 0.381)
		(layer "F.Cu")
		(net "GND")
	)
	(segment
		(start 113.989866 -220.855794)
		(end 113.989866 -220.319854)
		(width 0.2032)
		(layer "F.Cu")
		(net "GND")
	)
	(segment
		(start 293.799514 -201.56678)
		(end 292.694614 -201.56678)
		(width 0.381)
		(layer "F.Cu")
		(net "GND")
	)
	(segment
		(start 137.594594 -286.7533)
		(end 137.594594 -287.28924)
		(width 0.2032)
		(layer "F.Cu")
		(net "GND")
	)
	(segment
		(start 210.514946 -278.066754)
		(end 211.619846 -278.066754)
		(width 0.381)
		(layer "F.Cu")
		(net "GND")
	)
	(segment
		(start 129.966466 -245.27256)
		(end 129.966212 -245.272306)
		(width 0.2032)
		(layer "F.Cu")
		(net "GND")
	)
	(segment
		(start 49.959514 -245.76659)
		(end 51.064414 -245.76659)
		(width 0.381)
		(layer "F.Cu")
		(net "GND")
	)
	(segment
		(start 380.365762 -285.939484)
		(end 380.365762 -286.475424)
		(width 0.2032)
		(layer "F.Cu")
		(net "GND")
	)
	(segment
		(start 162.913314 -261.066788)
		(end 161.808414 -261.066788)
		(width 0.381)
		(layer "F.Cu")
		(net "GND")
	)
	(segment
		(start 19.784314 -258.516628)
		(end 20.889214 -258.516628)
		(width 0.381)
		(layer "F.Cu")
		(net "GND")
	)
	(segment
		(start 39.420546 -273.816572)
		(end 38.315646 -273.816572)
		(width 0.381)
		(layer "F.Cu")
		(net "GND")
	)
	(segment
		(start 176.896014 -280.61666)
		(end 178.000914 -280.61666)
		(width 0.381)
		(layer "F.Cu")
		(net "GND")
	)
	(segment
		(start 65.047114 -280.61666)
		(end 66.152014 -280.61666)
		(width 0.381)
		(layer "F.Cu")
		(net "GND")
	)
	(segment
		(start 260.180582 -202.416664)
		(end 259.075682 -202.416664)
		(width 0.381)
		(layer "F.Cu")
		(net "GND")
	)
	(segment
		(start 138.81989 -269.66164)
		(end 139.05103 -269.757398)
		(width 0.254)
		(layer "F.Cu")
		(net "GND")
	)
	(segment
		(start 65.047114 -264.466578)
		(end 66.152014 -264.466578)
		(width 0.381)
		(layer "F.Cu")
		(net "GND")
	)
	(segment
		(start 161.808414 -278.916638)
		(end 162.913314 -278.916638)
		(width 0.381)
		(layer "F.Cu")
		(net "GND")
	)
	(segment
		(start 56.398414 -295.916604)
		(end 57.503314 -295.916604)
		(width 0.381)
		(layer "F.Cu")
		(net "GND")
	)
	(segment
		(start 302.534574 -434.68671)
		(end 302.534574 -435.19598)
		(width 0.3556)
		(layer "F.Cu")
		(net "GND")
	)
	(segment
		(start 449.677282 -271.266666)
		(end 448.572382 -271.266666)
		(width 0.381)
		(layer "F.Cu")
		(net "GND")
	)
	(segment
		(start 326.246744 -344.801698)
		(end 326.246998 -344.801952)
		(width 0.1778)
		(layer "F.Cu")
		(net "GND")
	)
	(segment
		(start 343.243916 -286.7533)
		(end 343.243916 -287.288986)
		(width 0.254)
		(layer "F.Cu")
		(net "GND")
	)
	(segment
		(start 346.532962 -274.54479)
		(end 346.532962 -275.08073)
		(width 0.2032)
		(layer "F.Cu")
		(net "GND")
	)
	(segment
		(start 130.906266 -232.250488)
		(end 130.906012 -232.250234)
		(width 0.2032)
		(layer "F.Cu")
		(net "GND")
	)
	(segment
		(start 441.028582 -226.216718)
		(end 442.133482 -226.216718)
		(width 0.381)
		(layer "F.Cu")
		(net "GND")
	)
	(segment
		(start 200.632314 -230.466646)
		(end 201.737214 -230.466646)
		(width 0.381)
		(layer "F.Cu")
		(net "GND")
	)
	(segment
		(start 34.871914 -306.96662)
		(end 33.767014 -306.96662)
		(width 0.381)
		(layer "F.Cu")
		(net "GND")
	)
	(segment
		(start 285.150814 -223.666558)
		(end 286.255714 -223.666558)
		(width 0.381)
		(layer "F.Cu")
		(net "GND")
	)
	(segment
		(start 176.6824 -94.738698)
		(end 176.6824 -95.367348)
		(width 0.3556)
		(layer "F.Cu")
		(net "GND")
	)
	(segment
		(start 7.035546 -270.416782)
		(end 8.140446 -270.416782)
		(width 0.381)
		(layer "F.Cu")
		(net "GND")
	)
	(segment
		(start 26.223214 -232.166668)
		(end 27.328114 -232.166668)
		(width 0.381)
		(layer "F.Cu")
		(net "GND")
	)
	(segment
		(start 53.403246 -212.616796)
		(end 52.298346 -212.616796)
		(width 0.381)
		(layer "F.Cu")
		(net "GND")
	)
	(segment
		(start 354.051362 -282.683966)
		(end 354.051362 -283.219906)
		(width 0.254)
		(layer "F.Cu")
		(net "GND")
	)
	(segment
		(start 345.48318 -244.458744)
		(end 345.483434 -244.45849)
		(width 0.2032)
		(layer "F.Cu")
		(net "GND")
	)
	(segment
		(start 178.000914 -264.466578)
		(end 176.896014 -264.466578)
		(width 0.381)
		(layer "F.Cu")
		(net "GND")
	)
	(segment
		(start 60.947046 -281.466798)
		(end 62.051946 -281.466798)
		(width 0.381)
		(layer "F.Cu")
		(net "GND")
	)
	(segment
		(start 456.116182 -205.816708)
		(end 455.011282 -205.816708)
		(width 0.381)
		(layer "F.Cu")
		(net "GND")
	)
	(segment
		(start 448.572382 -306.96662)
		(end 447.467482 -306.96662)
		(width 0.381)
		(layer "F.Cu")
		(net "GND")
	)
	(segment
		(start 22.123146 -273.816572)
		(end 23.228046 -273.816572)
		(width 0.381)
		(layer "F.Cu")
		(net "GND")
	)
	(segment
		(start 441.028582 -316.316614)
		(end 442.133482 -316.316614)
		(width 0.381)
		(layer "F.Cu")
		(net "GND")
	)
	(segment
		(start 433.484782 -278.916638)
		(end 434.589682 -278.916638)
		(width 0.381)
		(layer "F.Cu")
		(net "GND")
	)
	(segment
		(start 377.436634 -246.086376)
		(end 377.436634 -245.55069)
		(width 0.2032)
		(layer "F.Cu")
		(net "GND")
	)
	(segment
		(start 200.632314 -198.166736)
		(end 201.737214 -198.166736)
		(width 0.381)
		(layer "F.Cu")
		(net "GND")
	)
	(segment
		(start 159.918146 -311.216802)
		(end 158.813246 -311.216802)
		(width 0.381)
		(layer "F.Cu")
		(net "GND")
	)
	(segment
		(start 384.139948 -271.834102)
		(end 384.136646 -271.834356)
		(width 0.254)
		(layer "F.Cu")
		(net "GND")
	)
	(segment
		(start 92.844112 -216.78646)
		(end 92.844112 -216.250774)
		(width 0.254)
		(layer "F.Cu")
		(net "GND")
	)
	(segment
		(start 332.5114 -59.587638)
		(end 332.397608 -59.473846)
		(width 0.2032)
		(layer "F.Cu")
		(net "GND")
	)
	(segment
		(start 188.988446 -315.46673)
		(end 190.093346 -315.46673)
		(width 0.381)
		(layer "F.Cu")
		(net "GND")
	)
	(segment
		(start 100.942648 -270.475456)
		(end 100.942648 -271.011396)
		(width 0.2032)
		(layer "F.Cu")
		(net "GND")
	)
	(segment
		(start 449.677282 -202.416664)
		(end 448.572382 -202.416664)
		(width 0.381)
		(layer "F.Cu")
		(net "GND")
	)
	(segment
		(start 328.244962 -55.953914)
		(end 329.441048 -55.968646)
		(width 0.2032)
		(layer "F.Cu")
		(net "GND")
	)
	(segment
		(start 340.78418 -216.250774)
		(end 340.784434 -216.25052)
		(width 0.254)
		(layer "F.Cu")
		(net "GND")
	)
	(segment
		(start 439.923682 -261.066788)
		(end 441.028582 -261.066788)
		(width 0.381)
		(layer "F.Cu")
		(net "GND")
	)
	(segment
		(start 290.355782 -241.516662)
		(end 291.460682 -241.516662)
		(width 0.381)
		(layer "F.Cu")
		(net "GND")
	)
	(segment
		(start 45.859446 -306.116736)
		(end 46.964346 -306.116736)
		(width 0.381)
		(layer "F.Cu")
		(net "GND")
	)
	(segment
		(start 349.24238 -246.08663)
		(end 349.242634 -246.086376)
		(width 0.2032)
		(layer "F.Cu")
		(net "GND")
	)
	(segment
		(start 42.415714 -294.216582)
		(end 41.310814 -294.216582)
		(width 0.381)
		(layer "F.Cu")
		(net "GND")
	)
	(segment
		(start 110.230666 -240.389156)
		(end 110.230666 -239.853724)
		(width 0.254)
		(layer "F.Cu")
		(net "GND")
	)
	(segment
		(start 372.73738 -223.297496)
		(end 372.73738 -222.76181)
		(width 0.254)
		(layer "F.Cu")
		(net "GND")
	)
	(segment
		(start 138.534648 -262.336534)
		(end 138.534648 -262.872474)
		(width 0.254)
		(layer "F.Cu")
		(net "GND")
	)
	(segment
		(start 345.554554 -42.94759)
		(end 345.15171 -43.350434)
		(width 0.2032)
		(layer "F.Cu")
		(net "GND")
	)
	(segment
		(start 138.064748 -283.219398)
		(end 138.064748 -283.219906)
		(width 0.254)
		(layer "F.Cu")
		(net "GND")
	)
	(segment
		(start 52.298346 -199.01662)
		(end 53.403246 -199.01662)
		(width 0.381)
		(layer "F.Cu")
		(net "GND")
	)
	(segment
		(start 334.315562 -282.683966)
		(end 334.315562 -283.219906)
		(width 0.2032)
		(layer "F.Cu")
		(net "GND")
	)
	(segment
		(start 384.595116 -285.6611)
		(end 384.594862 -285.661354)
		(width 0.2032)
		(layer "F.Cu")
		(net "GND")
	)
	(segment
		(start 340.401402 -58.020204)
		(end 339.901276 -57.605168)
		(width 0.254)
		(layer "F.Cu")
		(net "GND")
	)
	(segment
		(start 274.32889 -96.329754)
		(end 273.62658 -96.329754)
		(width 0.3556)
		(layer "F.Cu")
		(net "GND")
	)
	(segment
		(start 27.328114 -303.566576)
		(end 28.433014 -303.566576)
		(width 0.381)
		(layer "F.Cu")
		(net "GND")
	)
	(segment
		(start 444.472314 -265.316716)
		(end 445.577214 -265.316716)
		(width 0.381)
		(layer "F.Cu")
		(net "GND")
	)
	(segment
		(start 278.711914 -290.816792)
		(end 279.816814 -290.816792)
		(width 0.381)
		(layer "F.Cu")
		(net "GND")
	)
	(segment
		(start 436.928514 -221.96679)
		(end 438.033414 -221.96679)
		(width 0.381)
		(layer "F.Cu")
		(net "GND")
	)
	(segment
		(start 95.663512 -226.017582)
		(end 95.663766 -226.017328)
		(width 0.254)
		(layer "F.Cu")
		(net "GND")
	)
	(segment
		(start 145.28546 -126.630684)
		(end 145.28546 -127.265684)
		(width 0.3556)
		(layer "F.Cu")
		(net "GND")
	)
	(segment
		(start 276.373082 -295.916604)
		(end 275.268182 -295.916604)
		(width 0.381)
		(layer "F.Cu")
		(net "GND")
	)
	(segment
		(start 312.987182 -264.466578)
		(end 314.092082 -264.466578)
		(width 0.381)
		(layer "F.Cu")
		(net "GND")
	)
	(segment
		(start 367.678716 -282.405582)
		(end 367.678462 -282.405836)
		(width 0.254)
		(layer "F.Cu")
		(net "GND")
	)
	(segment
		(start 240.626392 -251.117608)
		(end 240.522252 -251.221748)
		(width 0.3556)
		(layer "F.Cu")
		(net "GND")
	)
	(segment
		(start 293.799514 -204.96657)
		(end 292.694614 -204.96657)
		(width 0.381)
		(layer "F.Cu")
		(net "GND")
	)
	(segment
		(start 99.377246 -355.866192)
		(end 99.640136 -355.866192)
		(width 0.381)
		(layer "F.Cu")
		(net "GND")
	)
	(segment
		(start 91.544648 -286.7533)
		(end 91.544648 -287.28924)
		(width 0.254)
		(layer "F.Cu")
		(net "GND")
	)
	(segment
		(start 23.650702 -404.842218)
		(end 23.041102 -404.842218)
		(width 0.3556)
		(layer "F.Cu")
		(net "GND")
	)
	(segment
		(start 144.8308 -94.546166)
		(end 145.175224 -94.89059)
		(width 0.3556)
		(layer "F.Cu")
		(net "GND")
	)
	(segment
		(start 46.750478 -98.824034)
		(end 47.360078 -98.824034)
		(width 0.3556)
		(layer "F.Cu")
		(net "GND")
	)
	(segment
		(start 107.051094 -274.54479)
		(end 107.051094 -275.080476)
		(width 0.254)
		(layer "F.Cu")
		(net "GND")
	)
	(segment
		(start 119.158512 -216.250774)
		(end 119.158766 -216.25052)
		(width 0.254)
		(layer "F.Cu")
		(net "GND")
	)
	(segment
		(start 271.168114 -204.96657)
		(end 270.063214 -204.96657)
		(width 0.381)
		(layer "F.Cu")
		(net "GND")
	)
	(segment
		(start 382.245362 -266.405868)
		(end 382.245616 -266.941808)
		(width 0.2032)
		(layer "F.Cu")
		(net "GND")
	)
	(segment
		(start 115.039394 -264.500106)
		(end 115.039394 -264.50036)
		(width 0.254)
		(layer "F.Cu")
		(net "GND")
	)
	(segment
		(start 12.240514 -278.916638)
		(end 13.345414 -278.916638)
		(width 0.381)
		(layer "F.Cu")
		(net "GND")
	)
	(segment
		(start 96.133666 -240.389156)
		(end 96.133412 -240.388902)
		(width 0.2032)
		(layer "F.Cu")
		(net "GND")
	)
	(segment
		(start 308.402482 -435.663848)
		(end 308.760622 -435.663848)
		(width 0.3556)
		(layer "F.Cu")
		(net "GND")
	)
	(segment
		(start 11.135614 -289.966654)
		(end 12.240514 -289.966654)
		(width 0.381)
		(layer "F.Cu")
		(net "GND")
	)
	(segment
		(start 382.245362 -255.547368)
		(end 382.245616 -255.547622)
		(width 0.2032)
		(layer "F.Cu")
		(net "GND")
	)
	(segment
		(start 211.619846 -290.816792)
		(end 210.514946 -290.816792)
		(width 0.381)
		(layer "F.Cu")
		(net "GND")
	)
	(segment
		(start 11.135614 -282.316682)
		(end 12.240514 -282.316682)
		(width 0.381)
		(layer "F.Cu")
		(net "GND")
	)
	(segment
		(start 384.485134 -219.228162)
		(end 384.485134 -218.692222)
		(width 0.2032)
		(layer "F.Cu")
		(net "GND")
	)
	(segment
		(start 410.853382 -278.916638)
		(end 409.748482 -278.916638)
		(width 0.381)
		(layer "F.Cu")
		(net "GND")
	)
	(segment
		(start 377.43638 -220.041978)
		(end 377.436634 -219.506038)
		(width 0.254)
		(layer "F.Cu")
		(net "GND")
	)
	(segment
		(start 113.519712 -233.064304)
		(end 113.519712 -232.528618)
		(width 0.254)
		(layer "F.Cu")
		(net "GND")
	)
	(segment
		(start 312.987182 -245.76659)
		(end 314.092082 -245.76659)
		(width 0.381)
		(layer "F.Cu")
		(net "GND")
	)
	(segment
		(start 12.240514 -207.51673)
		(end 13.345414 -207.51673)
		(width 0.381)
		(layer "F.Cu")
		(net "GND")
	)
	(segment
		(start 188.988446 -203.266802)
		(end 187.883546 -203.266802)
		(width 0.381)
		(layer "F.Cu")
		(net "GND")
	)
	(segment
		(start 119.738648 -282.405582)
		(end 119.738394 -282.405836)
		(width 0.254)
		(layer "F.Cu")
		(net "GND")
	)
	(segment
		(start 15.684246 -258.516628)
		(end 14.579346 -258.516628)
		(width 0.381)
		(layer "F.Cu")
		(net "GND")
	)
	(segment
		(start 38.315646 -258.516628)
		(end 37.210746 -258.516628)
		(width 0.381)
		(layer "F.Cu")
		(net "GND")
	)
	(segment
		(start 368.70132 -413.50946)
		(end 369.368578 -413.50946)
		(width 0.3556)
		(layer "F.Cu")
		(net "GND")
	)
	(segment
		(start 405.648414 -309.51678)
		(end 406.753314 -309.51678)
		(width 0.381)
		(layer "F.Cu")
		(net "GND")
	)
	(segment
		(start 278.711914 -265.316716)
		(end 279.816814 -265.316716)
		(width 0.381)
		(layer "F.Cu")
		(net "GND")
	)
	(segment
		(start 33.072324 -393.17549)
		(end 32.350964 -393.17549)
		(width 0.4572)
		(layer "F.Cu")
		(net "GND")
	)
	(segment
		(start 345.15171 -44.349162)
		(end 345.552776 -43.948096)
		(width 0.2032)
		(layer "F.Cu")
		(net "GND")
	)
	(segment
		(start 114.569494 -264.778236)
		(end 114.569494 -265.314176)
		(width 0.254)
		(layer "F.Cu")
		(net "GND")
	)
	(segment
		(start 356.291134 -220.855794)
		(end 356.291134 -220.319854)
		(width 0.2032)
		(layer "F.Cu")
		(net "GND")
	)
	(segment
		(start 126.207012 -237.133638)
		(end 126.207012 -236.597952)
		(width 0.254)
		(layer "F.Cu")
		(net "GND")
	)
	(segment
		(start 281.707082 -228.766624)
		(end 282.811982 -228.766624)
		(width 0.381)
		(layer "F.Cu")
		(net "GND")
	)
	(segment
		(start 276.373082 -224.516696)
		(end 275.268182 -224.516696)
		(width 0.381)
		(layer "F.Cu")
		(net "GND")
	)
	(segment
		(start 130.436112 -216.250774)
		(end 130.436366 -216.25052)
		(width 0.254)
		(layer "F.Cu")
		(net "GND")
	)
	(segment
		(start 414.297114 -236.416596)
		(end 415.624264 -236.416596)
		(width 0.381)
		(layer "F.Cu")
		(net "GND")
	)
	(segment
		(start 304.338482 -233.86669)
		(end 305.443382 -233.86669)
		(width 0.381)
		(layer "F.Cu")
		(net "GND")
	)
	(segment
		(start 328.194162 -55.903114)
		(end 328.244962 -55.953914)
		(width 0.2032)
		(layer "F.Cu")
		(net "GND")
	)
	(segment
		(start 276.373082 -219.41663)
		(end 275.268182 -219.41663)
		(width 0.381)
		(layer "F.Cu")
		(net "GND")
	)
	(segment
		(start 200.632314 -314.616592)
		(end 201.737214 -314.616592)
		(width 0.381)
		(layer "F.Cu")
		(net "GND")
	)
	(segment
		(start 159.918146 -210.916774)
		(end 158.813246 -210.916774)
		(width 0.381)
		(layer "F.Cu")
		(net "GND")
	)
	(segment
		(start 453.121014 -307.816758)
		(end 452.016114 -307.816758)
		(width 0.381)
		(layer "F.Cu")
		(net "GND")
	)
	(segment
		(start 46.964346 -315.46673)
		(end 45.859446 -315.46673)
		(width 0.381)
		(layer "F.Cu")
		(net "GND")
	)
	(segment
		(start 135.605266 -219.228162)
		(end 135.605266 -218.692222)
		(width 0.2032)
		(layer "F.Cu")
		(net "GND")
	)
	(segment
		(start 136.527032 -260.31063)
		(end 136.184894 -260.430772)
		(width 0.088646)
		(layer "F.Cu")
		(net "GND")
	)
	(segment
		(start 433.484782 -215.166702)
		(end 434.589682 -215.166702)
		(width 0.381)
		(layer "F.Cu")
		(net "GND")
	)
	(segment
		(start 123.027694 -266.405868)
		(end 123.027948 -266.941808)
		(width 0.254)
		(layer "F.Cu")
		(net "GND")
	)
	(segment
		(start 236.599984 -58.764932)
		(end 237.615984 -58.764932)
		(width 0.381)
		(layer "F.Cu")
		(net "GND")
	)
	(segment
		(start 139.445492 -258.06654)
		(end 139.474448 -257.98907)
		(width 0.254)
		(layer "F.Cu")
		(net "GND")
	)
	(segment
		(start 432.379882 -305.266598)
		(end 433.484782 -305.266598)
		(width 0.381)
		(layer "F.Cu")
		(net "GND")
	)
	(segment
		(start 43.520614 -280.61666)
		(end 42.415714 -280.61666)
		(width 0.381)
		(layer "F.Cu")
		(net "GND")
	)
	(segment
		(start 429.384714 -216.016586)
		(end 430.489614 -216.016586)
		(width 0.381)
		(layer "F.Cu")
		(net "GND")
	)
	(segment
		(start 90.024966 -220.041724)
		(end 90.024966 -219.506038)
		(width 0.254)
		(layer "F.Cu")
		(net "GND")
	)
	(segment
		(start 65.047114 -216.866724)
		(end 66.367914 -216.866724)
		(width 0.381)
		(layer "F.Cu")
		(net "GND")
	)
	(segment
		(start 419.502082 -278.916638)
		(end 418.397182 -278.916638)
		(width 0.381)
		(layer "F.Cu")
		(net "GND")
	)
	(segment
		(start 8.140446 -225.36658)
		(end 9.245346 -225.36658)
		(width 0.381)
		(layer "F.Cu")
		(net "GND")
	)
	(segment
		(start 290.355782 -213.46668)
		(end 291.460682 -213.46668)
		(width 0.381)
		(layer "F.Cu")
		(net "GND")
	)
	(segment
		(start 15.036546 -388.161276)
		(end 14.452346 -388.161276)
		(width 0.3556)
		(layer "F.Cu")
		(net "GND")
	)
	(segment
		(start 63.942214 -239.81664)
		(end 65.047114 -239.81664)
		(width 0.381)
		(layer "F.Cu")
		(net "GND")
	)
	(segment
		(start 22.123146 -311.216802)
		(end 23.228046 -311.216802)
		(width 0.381)
		(layer "F.Cu")
		(net "GND")
	)
	(segment
		(start 260.180582 -303.566576)
		(end 259.075682 -303.566576)
		(width 0.381)
		(layer "F.Cu")
		(net "GND")
	)
	(segment
		(start 109.870494 -276.172676)
		(end 109.870494 -276.708616)
		(width 0.254)
		(layer "F.Cu")
		(net "GND")
	)
	(segment
		(start 134.305294 -259.894832)
		(end 134.305294 -260.430518)
		(width 0.2032)
		(layer "F.Cu")
		(net "GND")
	)
	(segment
		(start 368.50828 -233.877866)
		(end 368.50828 -233.34218)
		(width 0.254)
		(layer "F.Cu")
		(net "GND")
	)
	(segment
		(start 445.577214 -195.616576)
		(end 444.472314 -195.616576)
		(width 0.381)
		(layer "F.Cu")
		(net "GND")
	)
	(segment
		(start 65.047114 -282.316682)
		(end 66.367914 -282.316682)
		(width 0.381)
		(layer "F.Cu")
		(net "GND")
	)
	(segment
		(start 346.893134 -214.344758)
		(end 346.893134 -213.732618)
		(width 0.254)
		(layer "F.Cu")
		(net "GND")
	)
	(segment
		(start 138.894312 -234.69219)
		(end 139.364212 -234.970066)
		(width 0.254)
		(layer "F.Cu")
		(net "GND")
	)
	(segment
		(start 352.641916 -279.150064)
		(end 352.641662 -279.150318)
		(width 0.2032)
		(layer "F.Cu")
		(net "GND")
	)
	(segment
		(start 18.54708 -7.215124)
		(end 18.54708 -8.320024)
		(width 0.3556)
		(layer "F.Cu")
		(net "GND")
	)
	(segment
		(start 112.579912 -216.78646)
		(end 112.579912 -216.25052)
		(width 0.254)
		(layer "F.Cu")
		(net "GND")
	)
	(segment
		(start 350.652334 -232.250488)
		(end 350.652334 -231.714802)
		(width 0.2032)
		(layer "F.Cu")
		(net "GND")
	)
	(segment
		(start 359.110534 -232.250488)
		(end 359.11028 -232.250234)
		(width 0.2032)
		(layer "F.Cu")
		(net "GND")
	)
	(segment
		(start 190.093346 -238.966756)
		(end 188.988446 -238.966756)
		(width 0.381)
		(layer "F.Cu")
		(net "GND")
	)
	(segment
		(start 449.677282 -216.866724)
		(end 448.572382 -216.866724)
		(width 0.381)
		(layer "F.Cu")
		(net "GND")
	)
	(segment
		(start 193.088514 -200.716642)
		(end 191.983614 -200.716642)
		(width 0.381)
		(layer "F.Cu")
		(net "GND")
	)
	(segment
		(start 88.725248 -278.614378)
		(end 88.724994 -279.150318)
		(width 0.2032)
		(layer "F.Cu")
		(net "GND")
	)
	(segment
		(start 173.900846 -295.06672)
		(end 175.005746 -295.06672)
		(width 0.381)
		(layer "F.Cu")
		(net "GND")
	)
	(segment
		(start 335.615534 -219.228162)
		(end 335.615534 -218.692222)
		(width 0.2032)
		(layer "F.Cu")
		(net "GND")
	)
	(segment
		(start 463.659982 -310.366664)
		(end 462.555082 -310.366664)
		(width 0.381)
		(layer "F.Cu")
		(net "GND")
	)
	(segment
		(start 113.629694 -253.919736)
		(end 113.629948 -253.91999)
		(width 0.254)
		(layer "F.Cu")
		(net "GND")
	)
	(segment
		(start 85.905594 -281.869896)
		(end 85.905594 -282.405836)
		(width 0.2032)
		(layer "F.Cu")
		(net "GND")
	)
	(segment
		(start 418.397182 -306.96662)
		(end 417.292282 -306.96662)
		(width 0.381)
		(layer "F.Cu")
		(net "GND")
	)
	(segment
		(start 449.677282 -224.516696)
		(end 448.572382 -224.516696)
		(width 0.381)
		(layer "F.Cu")
		(net "GND")
	)
	(segment
		(start 122.447812 -248.527824)
		(end 122.447812 -247.992138)
		(width 0.2032)
		(layer "F.Cu")
		(net "GND")
	)
	(segment
		(start 428.279814 -210.916774)
		(end 429.384714 -210.916774)
		(width 0.381)
		(layer "F.Cu")
		(net "GND")
	)
	(segment
		(start 420.873428 -52.958492)
		(end 420.873428 -53.11648)
		(width 0.3556)
		(layer "F.Cu")
		(net "GND")
	)
	(segment
		(start 58.608214 -222.816674)
		(end 57.503314 -222.816674)
		(width 0.381)
		(layer "F.Cu")
		(net "GND")
	)
	(segment
		(start 311.882282 -222.816674)
		(end 312.987182 -222.816674)
		(width 0.381)
		(layer "F.Cu")
		(net "GND")
	)
	(segment
		(start 278.246078 -416.88385)
		(end 278.246078 -416.323018)
		(width 0.3556)
		(layer "F.Cu")
		(net "GND")
	)
	(segment
		(start 178.1556 -114.575336)
		(end 177.75555 -114.975386)
		(width 0.3556)
		(layer "F.Cu")
		(net "GND")
	)
	(segment
		(start 361.460034 -236.319568)
		(end 361.460034 -235.783882)
		(width 0.2032)
		(layer "F.Cu")
		(net "GND")
	)
	(segment
		(start 422.945814 -278.066754)
		(end 421.840914 -278.066754)
		(width 0.381)
		(layer "F.Cu")
		(net "GND")
	)
	(segment
		(start 57.503314 -308.666642)
		(end 58.608214 -308.666642)
		(width 0.381)
		(layer "F.Cu")
		(net "GND")
	)
	(segment
		(start 130.076448 -286.7533)
		(end 130.076448 -287.288986)
		(width 0.254)
		(layer "F.Cu")
		(net "GND")
	)
	(segment
		(start 352.641662 -265.592306)
		(end 352.641662 -266.128246)
		(width 0.2032)
		(layer "F.Cu")
		(net "GND")
	)
	(segment
		(start 52.298346 -315.46673)
		(end 53.403246 -315.46673)
		(width 0.381)
		(layer "F.Cu")
		(net "GND")
	)
	(segment
		(start 342.66378 -226.017582)
		(end 342.664034 -226.017328)
		(width 0.254)
		(layer "F.Cu")
		(net "GND")
	)
	(segment
		(start 350.18218 -216.250774)
		(end 350.182434 -216.25052)
		(width 0.254)
		(layer "F.Cu")
		(net "GND")
	)
	(segment
		(start 370.85778 -226.017582)
		(end 370.858034 -226.017328)
		(width 0.254)
		(layer "F.Cu")
		(net "GND")
	)
	(segment
		(start 98.6028 -413.343598)
		(end 98.6028 -414.371536)
		(width 0.3556)
		(layer "F.Cu")
		(net "GND")
	)
	(segment
		(start 260.180582 -286.56661)
		(end 259.075682 -286.56661)
		(width 0.381)
		(layer "F.Cu")
		(net "GND")
	)
	(segment
		(start 421.840914 -208.366614)
		(end 423.17162 -208.366614)
		(width 0.381)
		(layer "F.Cu")
		(net "GND")
	)
	(segment
		(start 343.822274 -49.859692)
		(end 343.819734 -49.859692)
		(width 0.254)
		(layer "F.Cu")
		(net "GND")
	)
	(segment
		(start 427.582076 -119.349012)
		(end 428.22368 -119.349012)
		(width 0.381)
		(layer "F.Cu")
		(net "GND")
	)
	(segment
		(start 86.845648 -278.614378)
		(end 86.375494 -278.336502)
		(width 0.254)
		(layer "F.Cu")
		(net "GND")
	)
	(segment
		(start 204.076046 -285.716726)
		(end 205.180946 -285.716726)
		(width 0.381)
		(layer "F.Cu")
		(net "GND")
	)
	(segment
		(start 30.771846 -195.616576)
		(end 31.876746 -195.616576)
		(width 0.381)
		(layer "F.Cu")
		(net "GND")
	)
	(segment
		(start 342.194134 -237.133892)
		(end 342.194134 -236.597952)
		(width 0.2032)
		(layer "F.Cu")
		(net "GND")
	)
	(segment
		(start 71.05396 -52.314348)
		(end 71.05396 -52.728876)
		(width 0.3556)
		(layer "F.Cu")
		(net "GND")
	)
	(segment
		(start 7.035546 -317.166752)
		(end 8.140446 -317.166752)
		(width 0.381)
		(layer "F.Cu")
		(net "GND")
	)
	(segment
		(start 294.904414 -229.616762)
		(end 293.799514 -229.616762)
		(width 0.381)
		(layer "F.Cu")
		(net "GND")
	)
	(segment
		(start 285.150814 -301.866808)
		(end 286.255714 -301.866808)
		(width 0.381)
		(layer "F.Cu")
		(net "GND")
	)
	(segment
		(start 128.556512 -247.714262)
		(end 128.556766 -247.714008)
		(width 0.2032)
		(layer "F.Cu")
		(net "GND")
	)
	(segment
		(start 398.446752 -8.320024)
		(end 398.446752 -7.215124)
		(width 0.3556)
		(layer "F.Cu")
		(net "GND")
	)
	(segment
		(start 68.31076 -55.367428)
		(end 68.522088 -55.578756)
		(width 0.254)
		(layer "F.Cu")
		(net "GND")
	)
	(segment
		(start 333.375762 -255.011682)
		(end 333.845662 -254.733552)
		(width 0.254)
		(layer "F.Cu")
		(net "GND")
	)
	(segment
		(start 432.74488 -128.761998)
		(end 432.74488 -129.377948)
		(width 0.3556)
		(layer "F.Cu")
		(net "GND")
	)
	(segment
		(start 96.689672 -425.303696)
		(end 96.689672 -424.770296)
		(width 0.3556)
		(layer "F.Cu")
		(net "GND")
	)
	(segment
		(start 427.129448 -126.81966)
		(end 427.826424 -126.81966)
		(width 0.254)
		(layer "F.Cu")
		(net "GND")
	)
	(segment
		(start 329.980798 -48.450246)
		(end 329.980036 -48.450246)
		(width 0.254)
		(layer "F.Cu")
		(net "GND")
	)
	(segment
		(start 97.992438 -354.48494)
		(end 97.314258 -354.48494)
		(width 0.3556)
		(layer "F.Cu")
		(net "GND")
	)
	(segment
		(start 157.708346 -309.51678)
		(end 158.813246 -309.51678)
		(width 0.381)
		(layer "F.Cu")
		(net "GND")
	)
	(segment
		(start 42.415714 -232.166668)
		(end 41.310814 -232.166668)
		(width 0.381)
		(layer "F.Cu")
		(net "GND")
	)
	(segment
		(start 158.813246 -315.46673)
		(end 159.918146 -315.46673)
		(width 0.381)
		(layer "F.Cu")
		(net "GND")
	)
	(segment
		(start 370.498116 -287.288986)
		(end 370.497862 -287.28924)
		(width 0.254)
		(layer "F.Cu")
		(net "GND")
	)
	(segment
		(start 294.904414 -273.816572)
		(end 293.799514 -273.816572)
		(width 0.381)
		(layer "F.Cu")
		(net "GND")
	)
	(segment
		(start 354.411534 -232.250488)
		(end 354.41128 -232.250234)
		(width 0.2032)
		(layer "F.Cu")
		(net "GND")
	)
	(segment
		(start 101.412294 -279.96388)
		(end 101.412548 -279.964134)
		(width 0.2032)
		(layer "F.Cu")
		(net "GND")
	)
	(segment
		(start 340.894162 -257.175254)
		(end 340.894162 -256.639314)
		(width 0.2032)
		(layer "F.Cu")
		(net "GND")
	)
	(segment
		(start 180.339746 -248.31675)
		(end 181.444646 -248.31675)
		(width 0.381)
		(layer "F.Cu")
		(net "GND")
	)
	(segment
		(start 414.297114 -261.916672)
		(end 415.402014 -261.916672)
		(width 0.381)
		(layer "F.Cu")
		(net "GND")
	)
	(segment
		(start 275.268182 -230.466646)
		(end 276.373082 -230.466646)
		(width 0.381)
		(layer "F.Cu")
		(net "GND")
	)
	(segment
		(start 85.905594 -273.730974)
		(end 86.375748 -273.453098)
		(width 0.2032)
		(layer "F.Cu")
		(net "GND")
	)
	(segment
		(start 105.641394 -267.220192)
		(end 105.641394 -267.755878)
		(width 0.254)
		(layer "F.Cu")
		(net "GND")
	)
	(segment
		(start 282.811982 -232.166668)
		(end 283.916882 -232.166668)
		(width 0.381)
		(layer "F.Cu")
		(net "GND")
	)
	(segment
		(start 419.502082 -288.266632)
		(end 418.397182 -288.266632)
		(width 0.381)
		(layer "F.Cu")
		(net "GND")
	)
	(segment
		(start 386.785866 -269.66164)
		(end 386.97281 -269.73911)
		(width 0.254)
		(layer "F.Cu")
		(net "GND")
	)
	(segment
		(start 122.917712 -241.203226)
		(end 122.917712 -240.667286)
		(width 0.254)
		(layer "F.Cu")
		(net "GND")
	)
	(segment
		(start 304.338482 -264.466578)
		(end 305.443382 -264.466578)
		(width 0.381)
		(layer "F.Cu")
		(net "GND")
	)
	(segment
		(start 94.364048 -283.497782)
		(end 94.364048 -284.033468)
		(width 0.254)
		(layer "F.Cu")
		(net "GND")
	)
	(segment
		(start 333.655416 -337.173316)
		(end 333.655416 -336.741008)
		(width 0.2032)
		(layer "F.Cu")
		(net "GND")
	)
	(segment
		(start 59.842146 -317.166752)
		(end 60.947046 -317.166752)
		(width 0.381)
		(layer "F.Cu")
		(net "GND")
	)
	(segment
		(start 137.484866 -225.739198)
		(end 137.484866 -225.203258)
		(width 0.254)
		(layer "F.Cu")
		(net "GND")
	)
	(segment
		(start 351.702116 -286.7533)
		(end 351.702116 -287.288986)
		(width 0.254)
		(layer "F.Cu")
		(net "GND")
	)
	(segment
		(start 186.649614 -295.916604)
		(end 185.544714 -295.916604)
		(width 0.381)
		(layer "F.Cu")
		(net "GND")
	)
	(segment
		(start 406.753314 -195.616576)
		(end 407.858214 -195.616576)
		(width 0.381)
		(layer "F.Cu")
		(net "GND")
	)
	(segment
		(start 212.798914 -21.637244)
		(end 213.369398 -21.06676)
		(width 0.3556)
		(layer "F.Cu")
		(net "GND")
	)
	(segment
		(start 303.5554 -55.286148)
		(end 303.5554 -55.133748)
		(width 0.508)
		(layer "F.Cu")
		(net "GND")
	)
	(segment
		(start 169.31894 -355.379274)
		(end 168.883584 -355.81463)
		(width 0.2032)
		(layer "F.Cu")
		(net "GND")
	)
	(segment
		(start 286.255714 -214.316564)
		(end 287.360614 -214.316564)
		(width 0.381)
		(layer "F.Cu")
		(net "GND")
	)
	(segment
		(start 194.193414 -266.1666)
		(end 193.088514 -266.1666)
		(width 0.381)
		(layer "F.Cu")
		(net "GND")
	)
	(segment
		(start 93.424248 -257.45313)
		(end 93.424248 -257.988816)
		(width 0.2032)
		(layer "F.Cu")
		(net "GND")
	)
	(segment
		(start 23.228046 -229.616762)
		(end 24.332946 -229.616762)
		(width 0.381)
		(layer "F.Cu")
		(net "GND")
	)
	(segment
		(start 194.193414 -233.86669)
		(end 193.088514 -233.86669)
		(width 0.381)
		(layer "F.Cu")
		(net "GND")
	)
	(segment
		(start 23.228046 -203.266802)
		(end 24.332946 -203.266802)
		(width 0.381)
		(layer "F.Cu")
		(net "GND")
	)
	(segment
		(start 128.666494 -259.894832)
		(end 128.666748 -260.430772)
		(width 0.2032)
		(layer "F.Cu")
		(net "GND")
	)
	(segment
		(start 449.573904 -117.193822)
		(end 448.8942 -117.193822)
		(width 0.3556)
		(layer "F.Cu")
		(net "GND")
	)
	(segment
		(start 60.947046 -231.316784)
		(end 62.051946 -231.316784)
		(width 0.381)
		(layer "F.Cu")
		(net "GND")
	)
	(segment
		(start 99.063048 -283.497782)
		(end 99.063048 -284.033468)
		(width 0.254)
		(layer "F.Cu")
		(net "GND")
	)
	(segment
		(start 188.988446 -248.31675)
		(end 187.883546 -248.31675)
		(width 0.381)
		(layer "F.Cu")
		(net "GND")
	)
	(segment
		(start 334.205834 -223.297496)
		(end 334.205834 -222.761556)
		(width 0.2032)
		(layer "F.Cu")
		(net "GND")
	)
	(segment
		(start 410.853382 -306.96662)
		(end 411.958282 -306.96662)
		(width 0.381)
		(layer "F.Cu")
		(net "GND")
	)
	(segment
		(start 199.527414 -297.616626)
		(end 200.632314 -297.616626)
		(width 0.381)
		(layer "F.Cu")
		(net "GND")
	)
	(segment
		(start 127.726694 -253.919482)
		(end 127.726948 -253.919736)
		(width 0.2032)
		(layer "F.Cu")
		(net "GND")
	)
	(segment
		(start 20.346924 -7.215124)
		(end 20.346924 -8.320024)
		(width 0.3556)
		(layer "F.Cu")
		(net "GND")
	)
	(segment
		(start 158.813246 -283.166566)
		(end 160.121346 -283.166566)
		(width 0.381)
		(layer "F.Cu")
		(net "GND")
	)
	(segment
		(start 262.519414 -210.916774)
		(end 263.624314 -210.916774)
		(width 0.381)
		(layer "F.Cu")
		(net "GND")
	)
	(segment
		(start 92.844112 -222.76181)
		(end 92.844366 -222.761556)
		(width 0.254)
		(layer "F.Cu")
		(net "GND")
	)
	(segment
		(start 360.51998 -220.041978)
		(end 360.520234 -220.041724)
		(width 0.254)
		(layer "F.Cu")
		(net "GND")
	)
	(segment
		(start 56.398414 -278.916638)
		(end 57.503314 -278.916638)
		(width 0.381)
		(layer "F.Cu")
		(net "GND")
	)
	(segment
		(start 365.380524 -385.819904)
		(end 365.829342 -385.819904)
		(width 0.3556)
		(layer "F.Cu")
		(net "GND")
	)
	(segment
		(start 271.168114 -234.716574)
		(end 270.063214 -234.716574)
		(width 0.381)
		(layer "F.Cu")
		(net "GND")
	)
	(segment
		(start 125.737112 -249.342148)
		(end 125.737366 -249.341894)
		(width 0.2032)
		(layer "F.Cu")
		(net "GND")
	)
	(segment
		(start 7.035546 -203.266802)
		(end 8.140446 -203.266802)
		(width 0.381)
		(layer "F.Cu")
		(net "GND")
	)
	(segment
		(start 377.076716 -283.497782)
		(end 377.076716 -284.033468)
		(width 0.254)
		(layer "F.Cu")
		(net "GND")
	)
	(segment
		(start 164.018214 -261.066788)
		(end 162.913314 -261.066788)
		(width 0.381)
		(layer "F.Cu")
		(net "GND")
	)
	(segment
		(start 38.45687 -10.16508)
		(end 38.45687 -11.26998)
		(width 0.3556)
		(layer "F.Cu")
		(net "GND")
	)
	(segment
		(start 15.684246 -223.666558)
		(end 16.789146 -223.666558)
		(width 0.381)
		(layer "F.Cu")
		(net "GND")
	)
	(segment
		(start 194.193414 -221.116652)
		(end 193.088514 -221.116652)
		(width 0.381)
		(layer "F.Cu")
		(net "GND")
	)
	(segment
		(start 84.856066 -224.111566)
		(end 84.856066 -223.575626)
		(width 0.254)
		(layer "F.Cu")
		(net "GND")
	)
	(segment
		(start 452.016114 -214.316564)
		(end 450.911214 -214.316564)
		(width 0.381)
		(layer "F.Cu")
		(net "GND")
	)
	(segment
		(start 118.328694 -284.311598)
		(end 118.328694 -284.847284)
		(width 0.254)
		(layer "F.Cu")
		(net "GND")
	)
	(segment
		(start 26.223214 -200.716642)
		(end 27.328114 -200.716642)
		(width 0.381)
		(layer "F.Cu")
		(net "GND")
	)
	(segment
		(start 127.616712 -236.319822)
		(end 127.616966 -236.319568)
		(width 0.2032)
		(layer "F.Cu")
		(net "GND")
	)
	(segment
		(start 342.304116 -278.614378)
		(end 342.304116 -279.150318)
		(width 0.254)
		(layer "F.Cu")
		(net "GND")
	)
	(segment
		(start 173.900846 -279.766776)
		(end 175.005746 -279.766776)
		(width 0.381)
		(layer "F.Cu")
		(net "GND")
	)
	(via
		(at 16.789146 -272.116804)
		(size 0.4572)
		(drill 0.2032)
		(layers "F.Cu" "B.Cu")
		(net "GND")
	)
	(via
		(at 412.956756 -10.16508)
		(size 0.508)
		(drill 0.254)
		(layers "F.Cu" "B.Cu")
		(net "GND")
	)
	(via
		(at 79.17053 -343.48293)
		(size 0.49022)
		(drill 0.254)
		(layers "F.Cu" "B.Cu")
		(net "GND")
	)
	(via
		(at 383.655062 -279.150318)
		(size 0.4572)
		(drill 0.2032)
		(layers "F.Cu" "B.Cu")
		(net "GND")
	)
	(via
		(at 210.514946 -261.916672)
		(size 0.4572)
		(drill 0.2032)
		(layers "F.Cu" "B.Cu")
		(net "GND")
	)
	(via
		(at 357.700834 -229.272846)
		(size 0.4572)
		(drill 0.2032)
		(layers "F.Cu" "B.Cu")
		(net "GND")
	)
	(via
		(at 41.308274 -355.531928)
		(size 0.49022)
		(drill 0.254)
		(layers "F.Cu" "B.Cu")
		(net "GND")
	)
	(via
		(at 136.258554 -407.00452)
		(size 0.4064)
		(drill 0.2032)
		(layers "F.Cu" "B.Cu")
		(net "GND")
	)
	(via
		(at 296.578782 -312.91657)
		(size 0.4572)
		(drill 0.2032)
		(layers "F.Cu" "B.Cu")
		(net "GND")
	)
	(via
		(at 18.130266 -19.770344)
		(size 0.508)
		(drill 0.254)
		(layers "F.Cu" "B.Cu")
		(net "GND")
	)
	(via
		(at 33.767014 -205.816708)
		(size 0.4572)
		(drill 0.2032)
		(layers "F.Cu" "B.Cu")
		(net "GND")
	)
	(via
		(at 335.615534 -236.597952)
		(size 0.4572)
		(drill 0.2032)
		(layers "F.Cu" "B.Cu")
		(net "GND")
	)
	(via
		(at 339.644736 -334.494124)
		(size 0.508)
		(drill 0.254)
		(layers "F.Cu" "B.Cu")
		(net "GND")
	)
	(via
		(at 159.918146 -260.21665)
		(size 0.4572)
		(drill 0.2032)
		(layers "F.Cu" "B.Cu")
		(net "GND")
	)
	(via
		(at 134.305294 -257.175254)
		(size 0.4572)
		(drill 0.2032)
		(layers "F.Cu" "B.Cu")
		(net "GND")
	)
	(via
		(at 393.046966 -7.215124)
		(size 0.508)
		(drill 0.254)
		(layers "F.Cu" "B.Cu")
		(net "GND")
	)
	(via
		(at 165.30066 -36.825428)
		(size 0.508)
		(drill 0.254)
		(layers "F.Cu" "B.Cu")
		(net "GND")
	)
	(via
		(at 179.105814 -275.516594)
		(size 0.4572)
		(drill 0.2032)
		(layers "F.Cu" "B.Cu")
		(net "GND")
	)
	(via
		(at 175.005746 -287.416748)
		(size 0.4572)
		(drill 0.2032)
		(layers "F.Cu" "B.Cu")
		(net "GND")
	)
	(via
		(at 114.099594 -266.128246)
		(size 0.4572)
		(drill 0.2032)
		(layers "F.Cu" "B.Cu")
		(net "GND")
	)
	(via
		(at 314.592208 -403.883876)
		(size 0.4064)
		(drill 0.2032)
		(layers "F.Cu" "B.Cu")
		(net "GND")
	)
	(via
		(at 2.764536 -371.270022)
		(size 0.508)
		(drill 0.254)
		(layers "F.Cu" "B.Cu")
		(net "GND")
	)
	(via
		(at 289.250882 -291.666676)
		(size 0.4572)
		(drill 0.2032)
		(layers "F.Cu" "B.Cu")
		(net "GND")
	)
	(via
		(at 419.502082 -200.716642)
		(size 0.4572)
		(drill 0.2032)
		(layers "F.Cu" "B.Cu")
		(net "GND")
	)
	(via
		(at 392.34999 -438.499758)
		(size 0.4572)
		(drill 0.2032)
		(layers "F.Cu" "B.Cu")
		(net "GND")
	)
	(via
		(at 28.433014 -282.316682)
		(size 0.4572)
		(drill 0.2032)
		(layers "F.Cu" "B.Cu")
		(net "GND")
	)
	(via
		(at 122.557794 -279.150318)
		(size 0.4572)
		(drill 0.2032)
		(layers "F.Cu" "B.Cu")
		(net "GND")
	)
	(via
		(at 285.150814 -268.71676)
		(size 0.4572)
		(drill 0.2032)
		(layers "F.Cu" "B.Cu")
		(net "GND")
	)
	(via
		(at 87.331042 -337.692238)
		(size 0.49022)
		(drill 0.254)
		(layers "F.Cu" "B.Cu")
		(net "GND")
	)
	(via
		(at 29.666946 -238.966756)
		(size 0.4572)
		(drill 0.2032)
		(layers "F.Cu" "B.Cu")
		(net "GND")
	)
	(via
		(at 411.958282 -233.86669)
		(size 0.4572)
		(drill 0.2032)
		(layers "F.Cu" "B.Cu")
		(net "GND")
	)
	(via
		(at 164.018214 -232.166668)
		(size 0.4572)
		(drill 0.2032)
		(layers "F.Cu" "B.Cu")
		(net "GND")
	)
	(via
		(at 415.402014 -309.51678)
		(size 0.4572)
		(drill 0.2032)
		(layers "F.Cu" "B.Cu")
		(net "GND")
	)
	(via
		(at 413.236664 -6.07949)
		(size 0.508)
		(drill 0.254)
		(layers "F.Cu" "B.Cu")
		(net "GND")
	)
	(via
		(at 340.541356 -404.51786)
		(size 0.4572)
		(drill 0.254)
		(layers "F.Cu" "B.Cu")
		(net "GND")
	)
	(via
		(at 297.82262 -412.24708)
		(size 0.508)
		(drill 0.254)
		(layers "F.Cu" "B.Cu")
		(net "GND")
	)
	(via
		(at 257.185414 -210.916774)
		(size 0.4572)
		(drill 0.2032)
		(layers "F.Cu" "B.Cu")
		(net "GND")
	)
	(via
		(at 127.616966 -216.25052)
		(size 0.4572)
		(drill 0.2032)
		(layers "F.Cu" "B.Cu")
		(net "GND")
	)
	(via
		(at 207.071214 -272.966688)
		(size 0.4572)
		(drill 0.2032)
		(layers "F.Cu" "B.Cu")
		(net "GND")
	)
	(via
		(at 403.305772 -19.125438)
		(size 0.508)
		(drill 0.254)
		(layers "F.Cu" "B.Cu")
		(net "GND")
	)
	(via
		(at 317.381636 -407.638504)
		(size 0.4572)
		(drill 0.254)
		(layers "F.Cu" "B.Cu")
		(net "GND")
	)
	(via
		(at 117.749066 -220.319854)
		(size 0.4572)
		(drill 0.2032)
		(layers "F.Cu" "B.Cu")
		(net "GND")
	)
	(via
		(at 304.338482 -198.166736)
		(size 0.4572)
		(drill 0.2032)
		(layers "F.Cu" "B.Cu")
		(net "GND")
	)
	(via
		(at 101.882194 -280.778204)
		(size 0.4572)
		(drill 0.2032)
		(layers "F.Cu" "B.Cu")
		(net "GND")
	)
	(via
		(at 24.332946 -229.616762)
		(size 0.4572)
		(drill 0.2032)
		(layers "F.Cu" "B.Cu")
		(net "GND")
	)
	(via
		(at 196.307964 -79.135732)
		(size 0.508)
		(drill 0.254)
		(layers "F.Cu" "B.Cu")
		(net "GND")
	)
	(via
		(at 164.101526 -400.200368)
		(size 0.4572)
		(drill 0.254)
		(layers "F.Cu" "B.Cu")
		(net "GND")
	)
	(via
		(at 104.281986 -334.282034)
		(size 0.49022)
		(drill 0.254)
		(layers "F.Cu" "B.Cu")
		(net "GND")
	)
	(via
		(at 170.090084 -323.434456)
		(size 0.4572)
		(drill 0.2032)
		(layers "F.Cu" "B.Cu")
		(net "GND")
	)
	(via
		(at 97.543112 -245.55069)
		(size 0.4572)
		(drill 0.2032)
		(layers "F.Cu" "B.Cu")
		(net "GND")
	)
	(via
		(at 338.90458 -226.017328)
		(size 0.4572)
		(drill 0.2032)
		(layers "F.Cu" "B.Cu")
		(net "GND")
	)
	(via
		(at 59.842146 -250.016772)
		(size 0.4572)
		(drill 0.2032)
		(layers "F.Cu" "B.Cu")
		(net "GND")
	)
	(via
		(at 379.896116 -272.639282)
		(size 0.4572)
		(drill 0.2032)
		(layers "F.Cu" "B.Cu")
		(net "GND")
	)
	(via
		(at 63.43269 -38.784276)
		(size 0.508)
		(drill 0.254)
		(layers "F.Cu" "B.Cu")
		(net "GND")
	)
	(via
		(at 424.836082 -289.966654)
		(size 0.4572)
		(drill 0.2032)
		(layers "F.Cu" "B.Cu")
		(net "GND")
	)
	(via
		(at 37.210746 -201.56678)
		(size 0.4572)
		(drill 0.2032)
		(layers "F.Cu" "B.Cu")
		(net "GND")
	)
	(via
		(at 123.78436 -416.903408)
		(size 0.508)
		(drill 0.254)
		(layers "F.Cu" "B.Cu")
		(net "GND")
	)
	(via
		(at 157.708346 -225.36658)
		(size 0.4572)
		(drill 0.2032)
		(layers "F.Cu" "B.Cu")
		(net "GND")
	)
	(via
		(at 147.349972 -430.299622)
		(size 0.4572)
		(drill 0.2032)
		(layers "F.Cu" "B.Cu")
		(net "GND")
	)
	(via
		(at 82.250026 -439.651394)
		(size 0.4572)
		(drill 0.2032)
		(layers "F.Cu" "B.Cu")
		(net "GND")
	)
	(via
		(at 380.366016 -263.686544)
		(size 0.4572)
		(drill 0.2032)
		(layers "F.Cu" "B.Cu")
		(net "GND")
	)
	(via
		(at 261.285482 -310.366664)
		(size 0.4572)
		(drill 0.2032)
		(layers "F.Cu" "B.Cu")
		(net "GND")
	)
	(via
		(at 470.940384 -13.305282)
		(size 0.508)
		(drill 0.254)
		(layers "F.Cu" "B.Cu")
		(net "GND")
	)
	(via
		(at 129.496312 -248.806208)
		(size 0.4572)
		(drill 0.2032)
		(layers "F.Cu" "B.Cu")
		(net "GND")
	)
	(via
		(at 309.992014 -307.816758)
		(size 0.4572)
		(drill 0.2032)
		(layers "F.Cu" "B.Cu")
		(net "GND")
	)
	(via
		(at 281.707082 -277.216616)
		(size 0.4572)
		(drill 0.2032)
		(layers "F.Cu" "B.Cu")
		(net "GND")
	)
	(via
		(at 414.070292 -178.828954)
		(size 0.49022)
		(drill 0.254)
		(layers "F.Cu" "B.Cu")
		(net "GND")
	)
	(via
		(at 207.071214 -232.166668)
		(size 0.4572)
		(drill 0.2032)
		(layers "F.Cu" "B.Cu")
		(net "GND")
	)
	(via
		(at 154.64282 -95.072708)
		(size 0.508)
		(drill 0.254)
		(layers "F.Cu" "B.Cu")
		(net "GND")
	)
	(via
		(at 205.243684 -319.446656)
		(size 0.4572)
		(drill 0.2032)
		(layers "F.Cu" "B.Cu")
		(net "GND")
	)
	(via
		(at 376.966734 -241.481102)
		(size 0.4572)
		(drill 0.2032)
		(layers "F.Cu" "B.Cu")
		(net "GND")
	)
	(via
		(at 389.093964 -441.225432)
		(size 0.508)
		(drill 0.254)
		(layers "F.Cu" "B.Cu")
		(net "GND")
	)
	(via
		(at 304.338482 -222.816674)
		(size 0.4572)
		(drill 0.2032)
		(layers "F.Cu" "B.Cu")
		(net "GND")
	)
	(via
		(at 52.298346 -233.016806)
		(size 0.4572)
		(drill 0.2032)
		(layers "F.Cu" "B.Cu")
		(net "GND")
	)
	(via
		(at 55.343806 -4.328668)
		(size 0.508)
		(drill 0.254)
		(layers "F.Cu" "B.Cu")
		(net "GND")
	)
	(via
		(at 349.352616 -266.941808)
		(size 0.4572)
		(drill 0.2032)
		(layers "F.Cu" "B.Cu")
		(net "GND")
	)
	(via
		(at 450.911214 -233.016806)
		(size 0.4572)
		(drill 0.2032)
		(layers "F.Cu" "B.Cu")
		(net "GND")
	)
	(via
		(at 148.872702 -410.664152)
		(size 0.4572)
		(drill 0.254)
		(layers "F.Cu" "B.Cu")
		(net "GND")
	)
	(via
		(at 411.958282 -210.066636)
		(size 0.4572)
		(drill 0.2032)
		(layers "F.Cu" "B.Cu")
		(net "GND")
	)
	(via
		(at 417.07689 -410.030168)
		(size 0.4064)
		(drill 0.2032)
		(layers "F.Cu" "B.Cu")
		(net "GND")
	)
	(via
		(at 56.398414 -294.216582)
		(size 0.4572)
		(drill 0.2032)
		(layers "F.Cu" "B.Cu")
		(net "GND")
	)
	(via
		(at 207.071214 -216.866724)
		(size 0.4572)
		(drill 0.2032)
		(layers "F.Cu" "B.Cu")
		(net "GND")
	)
	(via
		(at 49.40681 -165.463982)
		(size 0.508)
		(drill 0.254)
		(layers "F.Cu" "B.Cu")
		(net "GND")
	)
	(via
		(at 95.645478 -332.56601)
		(size 0.49022)
		(drill 0.254)
		(layers "F.Cu" "B.Cu")
		(net "GND")
	)
	(via
		(at 409.401772 -18.491454)
		(size 0.508)
		(drill 0.254)
		(layers "F.Cu" "B.Cu")
		(net "GND")
	)
	(via
		(at 92.484448 -257.98907)
		(size 0.4572)
		(drill 0.2032)
		(layers "F.Cu" "B.Cu")
		(net "GND")
	)
	(via
		(at 217.062558 -25.311354)
		(size 0.508)
		(drill 0.254)
		(layers "F.Cu" "B.Cu")
		(net "GND")
	)
	(via
		(at 137.553954 -343.48293)
		(size 0.49022)
		(drill 0.254)
		(layers "F.Cu" "B.Cu")
		(net "GND")
	)
	(via
		(at 338.074762 -283.219906)
		(size 0.4572)
		(drill 0.2032)
		(layers "F.Cu" "B.Cu")
		(net "GND")
	)
	(via
		(at 201.737214 -198.166736)
		(size 0.4572)
		(drill 0.2032)
		(layers "F.Cu" "B.Cu")
		(net "GND")
	)
	(via
		(at 339.374734 -247.992138)
		(size 0.4572)
		(drill 0.2032)
		(layers "F.Cu" "B.Cu")
		(net "GND")
	)
	(via
		(at 92.844366 -234.15625)
		(size 0.4572)
		(drill 0.2032)
		(layers "F.Cu" "B.Cu")
		(net "GND")
	)
	(via
		(at 383.655062 -282.405836)
		(size 0.4572)
		(drill 0.2032)
		(layers "F.Cu" "B.Cu")
		(net "GND")
	)
	(via
		(at 128.556766 -222.761556)
		(size 0.4572)
		(drill 0.2032)
		(layers "F.Cu" "B.Cu")
		(net "GND")
	)
	(via
		(at 199.527414 -297.616626)
		(size 0.4572)
		(drill 0.2032)
		(layers "F.Cu" "B.Cu")
		(net "GND")
	)
	(via
		(at 363.919262 -272.639282)
		(size 0.4572)
		(drill 0.2032)
		(layers "F.Cu" "B.Cu")
		(net "GND")
	)
	(via
		(at 127.907288 -358.149906)
		(size 0.508)
		(drill 0.254)
		(layers "F.Cu" "B.Cu")
		(net "GND")
	)
	(via
		(at 98.123248 -254.733552)
		(size 0.4572)
		(drill 0.2032)
		(layers "F.Cu" "B.Cu")
		(net "GND")
	)
	(via
		(at 445.577214 -311.216802)
		(size 0.4572)
		(drill 0.2032)
		(layers "F.Cu" "B.Cu")
		(net "GND")
	)
	(via
		(at 129.136394 -266.128246)
		(size 0.4572)
		(drill 0.2032)
		(layers "F.Cu" "B.Cu")
		(net "GND")
	)
	(via
		(at 27.77109 -18.246344)
		(size 0.508)
		(drill 0.254)
		(layers "F.Cu" "B.Cu")
		(net "GND")
	)
	(via
		(at 86.845394 -285.661354)
		(size 0.4572)
		(drill 0.2032)
		(layers "F.Cu" "B.Cu")
		(net "GND")
	)
	(via
		(at 460.80934 -387.55701)
		(size 0.508)
		(drill 0.254)
		(layers "F.Cu" "B.Cu")
		(net "GND")
	)
	(via
		(at 74.536808 -21.839682)
		(size 0.508)
		(drill 0.254)
		(layers "F.Cu" "B.Cu")
		(net "GND")
	)
	(via
		(at 212.724746 -206.666592)
		(size 0.4572)
		(drill 0.2032)
		(layers "F.Cu" "B.Cu")
		(net "GND")
	)
	(via
		(at 427.126908 -123.23572)
		(size 0.508)
		(drill 0.254)
		(layers "F.Cu" "B.Cu")
		(net "GND")
	)
	(via
		(at 35.93338 -345.2114)
		(size 0.508)
		(drill 0.254)
		(layers "F.Cu" "B.Cu")
		(net "GND")
	)
	(via
		(at 384.863848 -344.90533)
		(size 0.49022)
		(drill 0.254)
		(layers "F.Cu" "B.Cu")
		(net "GND")
	)
	(via
		(at 86.735666 -236.597952)
		(size 0.4318)
		(drill 0.2032)
		(layers "F.Cu" "B.Cu")
		(net "GND")
	)
	(via
		(at 434.589682 -280.61666)
		(size 0.4572)
		(drill 0.2032)
		(layers "F.Cu" "B.Cu")
		(net "GND")
	)
	(via
		(at 51.064414 -264.466578)
		(size 0.4572)
		(drill 0.2032)
		(layers "F.Cu" "B.Cu")
		(net "GND")
	)
	(via
		(at 115.483894 -405.57577)
		(size 0.508)
		(drill 0.254)
		(layers "F.Cu" "B.Cu")
		(net "GND")
	)
	(via
		(at 187.49518 -359.20299)
		(size 0.508)
		(drill 0.254)
		(layers "F.Cu" "B.Cu")
		(net "GND")
	)
	(via
		(at 292.8493 -410.58338)
		(size 0.508)
		(drill 0.254)
		(layers "F.Cu" "B.Cu")
		(net "GND")
	)
	(via
		(at 369.558062 -279.150318)
		(size 0.4572)
		(drill 0.2032)
		(layers "F.Cu" "B.Cu")
		(net "GND")
	)
	(via
		(at 109.06633 -59.070748)
		(size 0.508)
		(drill 0.254)
		(layers "F.Cu" "B.Cu")
		(net "GND")
	)
	(via
		(at 442.133482 -288.266632)
		(size 0.4572)
		(drill 0.2032)
		(layers "F.Cu" "B.Cu")
		(net "GND")
	)
	(via
		(at 130.493262 -407.638504)
		(size 0.4572)
		(drill 0.254)
		(layers "F.Cu" "B.Cu")
		(net "GND")
	)
	(via
		(at 365.799116 -280.778204)
		(size 0.4572)
		(drill 0.2032)
		(layers "F.Cu" "B.Cu")
		(net "GND")
	)
	(via
		(at 342.66378 -234.15625)
		(size 0.4572)
		(drill 0.2032)
		(layers "F.Cu" "B.Cu")
		(net "GND")
	)
	(via
		(at 314.307982 -284.866588)
		(size 0.4572)
		(drill 0.2032)
		(layers "F.Cu" "B.Cu")
		(net "GND")
	)
	(via
		(at 462.555082 -222.816674)
		(size 0.4572)
		(drill 0.2032)
		(layers "F.Cu" "B.Cu")
		(net "GND")
	)
	(via
		(at 420.736014 -216.016586)
		(size 0.4572)
		(drill 0.2032)
		(layers "F.Cu" "B.Cu")
		(net "GND")
	)
	(via
		(at 212.724746 -246.616728)
		(size 0.4572)
		(drill 0.2032)
		(layers "F.Cu" "B.Cu")
		(net "GND")
	)
	(via
		(at 22.123146 -265.316716)
		(size 0.4572)
		(drill 0.2032)
		(layers "F.Cu" "B.Cu")
		(net "GND")
	)
	(via
		(at 287.360614 -236.416596)
		(size 0.4572)
		(drill 0.2032)
		(layers "F.Cu" "B.Cu")
		(net "GND")
	)
	(via
		(at 277.607014 -315.46673)
		(size 0.4572)
		(drill 0.2032)
		(layers "F.Cu" "B.Cu")
		(net "GND")
	)
	(via
		(at 420.93388 -157.648148)
		(size 0.508)
		(drill 0.254)
		(layers "F.Cu" "B.Cu")
		(net "GND")
	)
	(via
		(at 216.824814 -284.866588)
		(size 0.4572)
		(drill 0.2032)
		(layers "F.Cu" "B.Cu")
		(net "GND")
	)
	(via
		(at 195.867274 -28.394152)
		(size 0.508)
		(drill 0.254)
		(layers "F.Cu" "B.Cu")
		(net "GND")
	)
	(via
		(at 272.273014 -298.466764)
		(size 0.4572)
		(drill 0.2032)
		(layers "F.Cu" "B.Cu")
		(net "GND")
	)
	(via
		(at 221.1578 -97.13341)
		(size 0.508)
		(drill 0.254)
		(layers "F.Cu" "B.Cu")
		(net "GND")
	)
	(via
		(at 447.987674 -72.089518)
		(size 0.508)
		(drill 0.254)
		(layers "F.Cu" "B.Cu")
		(net "GND")
	)
	(via
		(at 372.847362 -289.807142)
		(size 0.4572)
		(drill 0.2032)
		(layers "F.Cu" "B.Cu")
		(net "GND")
	)
	(via
		(at 311.666382 -272.966688)
		(size 0.4572)
		(drill 0.2032)
		(layers "F.Cu" "B.Cu")
		(net "GND")
	)
	(via
		(at 396.646908 -10.16508)
		(size 0.508)
		(drill 0.254)
		(layers "F.Cu" "B.Cu")
		(net "GND")
	)
	(via
		(at 2.764536 -305.230022)
		(size 0.508)
		(drill 0.254)
		(layers "F.Cu" "B.Cu")
		(net "GND")
	)
	(via
		(at 129.74701 -17.655032)
		(size 0.508)
		(drill 0.254)
		(layers "F.Cu" "B.Cu")
		(net "GND")
	)
	(via
		(at 133.255512 -237.411514)
		(size 0.4572)
		(drill 0.2032)
		(layers "F.Cu" "B.Cu")
		(net "GND")
	)
	(via
		(at 209.281014 -222.816674)
		(size 0.4572)
		(drill 0.2032)
		(layers "F.Cu" "B.Cu")
		(net "GND")
	)
	(via
		(at 302.448214 -244.916706)
		(size 0.4572)
		(drill 0.2032)
		(layers "F.Cu" "B.Cu")
		(net "GND")
	)
	(via
		(at 285.150814 -195.616576)
		(size 0.4572)
		(drill 0.2032)
		(layers "F.Cu" "B.Cu")
		(net "GND")
	)
	(via
		(at 120.525286 -326.859392)
		(size 0.508)
		(drill 0.254)
		(layers "F.Cu" "B.Cu")
		(net "GND")
	)
	(via
		(at 179.105814 -222.816674)
		(size 0.4572)
		(drill 0.2032)
		(layers "F.Cu" "B.Cu")
		(net "GND")
	)
	(via
		(at 56.398414 -239.81664)
		(size 0.4572)
		(drill 0.2032)
		(layers "F.Cu" "B.Cu")
		(net "GND")
	)
	(via
		(at 350.841056 -245.337584)
		(size 0.4572)
		(drill 0.2032)
		(layers "F.Cu" "B.Cu")
		(net "GND")
	)
	(via
		(at 175.44288 -124.958348)
		(size 0.508)
		(drill 0.254)
		(layers "F.Cu" "B.Cu")
		(net "GND")
	)
	(via
		(at 15.58036 -97.627948)
		(size 0.508)
		(drill 0.254)
		(layers "F.Cu" "B.Cu")
		(net "GND")
	)
	(via
		(at 139.364212 -239.853216)
		(size 0.4572)
		(drill 0.2032)
		(layers "F.Cu" "B.Cu")
		(net "GND")
	)
	(via
		(at 425.7802 -55.819548)
		(size 0.508)
		(drill 0.254)
		(layers "F.Cu" "B.Cu")
		(net "GND")
	)
	(via
		(at 88.950546 -409.396184)
		(size 0.4572)
		(drill 0.254)
		(layers "F.Cu" "B.Cu")
		(net "GND")
	)
	(via
		(at 61.250068 -433.747164)
		(size 0.4572)
		(drill 0.2032)
		(layers "F.Cu" "B.Cu")
		(net "GND")
	)
	(via
		(at 340.528402 -330.454254)
		(size 0.508)
		(drill 0.254)
		(layers "F.Cu" "B.Cu")
		(net "GND")
	)
	(via
		(at 63.726314 -228.766624)
		(size 0.4572)
		(drill 0.2032)
		(layers "F.Cu" "B.Cu")
		(net "GND")
	)
	(via
		(at 372.847616 -278.336502)
		(size 0.4572)
		(drill 0.2032)
		(layers "F.Cu" "B.Cu")
		(net "GND")
	)
	(via
		(at 167.164766 -403.249892)
		(size 0.4572)
		(drill 0.254)
		(layers "F.Cu" "B.Cu")
		(net "GND")
	)
	(via
		(at 128.688846 -409.396184)
		(size 0.4572)
		(drill 0.254)
		(layers "F.Cu" "B.Cu")
		(net "GND")
	)
	(via
		(at 101.882194 -272.639282)
		(size 0.4572)
		(drill 0.2032)
		(layers "F.Cu" "B.Cu")
		(net "GND")
	)
	(via
		(at 381.40005 -410.030168)
		(size 0.4064)
		(drill 0.2032)
		(layers "F.Cu" "B.Cu")
		(net "GND")
	)
	(via
		(at 425.705524 -6.07949)
		(size 0.508)
		(drill 0.254)
		(layers "F.Cu" "B.Cu")
		(net "GND")
	)
	(via
		(at 407.858214 -258.516628)
		(size 0.4572)
		(drill 0.2032)
		(layers "F.Cu" "B.Cu")
		(net "GND")
	)
	(via
		(at 361.887516 -331.776832)
		(size 0.49022)
		(drill 0.254)
		(layers "F.Cu" "B.Cu")
		(net "GND")
	)
	(via
		(at 325.772272 -54.031388)
		(size 0.49022)
		(drill 0.254)
		(layers "F.Cu" "B.Cu")
		(net "GND")
	)
	(via
		(at 121.199148 -338.86013)
		(size 0.508)
		(drill 0.254)
		(layers "F.Cu" "B.Cu")
		(net "GND")
	)
	(via
		(at 39.420546 -240.666778)
		(size 0.4572)
		(drill 0.2032)
		(layers "F.Cu" "B.Cu")
		(net "GND")
	)
	(via
		(at 274.163282 -204.116686)
		(size 0.4572)
		(drill 0.2032)
		(layers "F.Cu" "B.Cu")
		(net "GND")
	)
	(via
		(at 338.394548 -55.498746)
		(size 0.4572)
		(drill 0.2032)
		(layers "F.Cu" "B.Cu")
		(net "GND")
	)
	(via
		(at 93.894148 -255.547622)
		(size 0.4572)
		(drill 0.2032)
		(layers "F.Cu" "B.Cu")
		(net "GND")
	)
	(via
		(at 442.133482 -284.866588)
		(size 0.4572)
		(drill 0.2032)
		(layers "F.Cu" "B.Cu")
		(net "GND")
	)
	(via
		(at 22.123146 -283.166566)
		(size 0.4572)
		(drill 0.2032)
		(layers "F.Cu" "B.Cu")
		(net "GND")
	)
	(via
		(at 369.918234 -222.761556)
		(size 0.4572)
		(drill 0.2032)
		(layers "F.Cu" "B.Cu")
		(net "GND")
	)
	(via
		(at 191.8208 -75.199748)
		(size 0.508)
		(drill 0.254)
		(layers "F.Cu" "B.Cu")
		(net "GND")
	)
	(via
		(at 460.664814 -206.666592)
		(size 0.4572)
		(drill 0.2032)
		(layers "F.Cu" "B.Cu")
		(net "GND")
	)
	(via
		(at 44.754546 -236.416596)
		(size 0.4572)
		(drill 0.2032)
		(layers "F.Cu" "B.Cu")
		(net "GND")
	)
	(via
		(at 89.555066 -217.064336)
		(size 0.4572)
		(drill 0.2032)
		(layers "F.Cu" "B.Cu")
		(net "GND")
	)
	(via
		(at 117.89664 -403.128988)
		(size 0.508)
		(drill 0.254)
		(layers "F.Cu" "B.Cu")
		(net "GND")
	)
	(via
		(at 11.135614 -238.116618)
		(size 0.4572)
		(drill 0.2032)
		(layers "F.Cu" "B.Cu")
		(net "GND")
	)
	(via
		(at 407.866596 -16.967454)
		(size 0.508)
		(drill 0.254)
		(layers "F.Cu" "B.Cu")
		(net "GND")
	)
	(via
		(at 183.894222 -353.201478)
		(size 0.49022)
		(drill 0.254)
		(layers "F.Cu" "B.Cu")
		(net "GND")
	)
	(via
		(at 105.061766 -216.25052)
		(size 0.4572)
		(drill 0.2032)
		(layers "F.Cu" "B.Cu")
		(net "GND")
	)
	(via
		(at 304.122582 -238.116618)
		(size 0.4572)
		(drill 0.2032)
		(layers "F.Cu" "B.Cu")
		(net "GND")
	)
	(via
		(at 110.700566 -219.506038)
		(size 0.4572)
		(drill 0.2032)
		(layers "F.Cu" "B.Cu")
		(net "GND")
	)
	(via
		(at 249.87504 -107.770168)
		(size 0.508)
		(drill 0.254)
		(layers "F.Cu" "B.Cu")
		(net "GND")
	)
	(via
		(at 267.469112 -62.615572)
		(size 0.508)
		(drill 0.254)
		(layers "F.Cu" "B.Cu")
		(net "GND")
	)
	(via
		(at 457.5683 -388.06882)
		(size 0.508)
		(drill 0.254)
		(layers "F.Cu" "B.Cu")
		(net "GND")
	)
	(via
		(at 262.519414 -281.466798)
		(size 0.4572)
		(drill 0.2032)
		(layers "F.Cu" "B.Cu")
		(net "GND")
	)
	(via
		(at 16.789146 -287.416748)
		(size 0.4572)
		(drill 0.2032)
		(layers "F.Cu" "B.Cu")
		(net "GND")
	)
	(via
		(at 422.142412 -18.491454)
		(size 0.508)
		(drill 0.254)
		(layers "F.Cu" "B.Cu")
		(net "GND")
	)
	(via
		(at 41.310814 -250.866656)
		(size 0.4572)
		(drill 0.2032)
		(layers "F.Cu" "B.Cu")
		(net "GND")
	)
	(via
		(at 102.170484 -424.62323)
		(size 0.508)
		(drill 0.254)
		(layers "F.Cu" "B.Cu")
		(net "GND")
	)
	(via
		(at 268.829282 -204.116686)
		(size 0.4572)
		(drill 0.2032)
		(layers "F.Cu" "B.Cu")
		(net "GND")
	)
	(via
		(at 447.62039 -74.964798)
		(size 0.508)
		(drill 0.254)
		(layers "F.Cu" "B.Cu")
		(net "GND")
	)
	(via
		(at 403.846792 -12.37488)
		(size 0.508)
		(drill 0.254)
		(layers "F.Cu" "B.Cu")
		(net "GND")
	)
	(via
		(at 168.872154 -410.030168)
		(size 0.4064)
		(drill 0.2032)
		(layers "F.Cu" "B.Cu")
		(net "GND")
	)
	(via
		(at 154.999182 -409.396184)
		(size 0.4572)
		(drill 0.254)
		(layers "F.Cu" "B.Cu")
		(net "GND")
	)
	(via
		(at 182.549546 -276.366732)
		(size 0.4572)
		(drill 0.2032)
		(layers "F.Cu" "B.Cu")
		(net "GND")
	)
	(via
		(at 281.707082 -215.166702)
		(size 0.4572)
		(drill 0.2032)
		(layers "F.Cu" "B.Cu")
		(net "GND")
	)
	(via
		(at 85.324696 -217.878406)
		(size 0.4572)
		(drill 0.2032)
		(layers "F.Cu" "B.Cu")
		(net "GND")
	)
	(via
		(at 349.822262 -274.266914)
		(size 0.4572)
		(drill 0.2032)
		(layers "F.Cu" "B.Cu")
		(net "GND")
	)
	(via
		(at 300.238414 -238.966756)
		(size 0.4572)
		(drill 0.2032)
		(layers "F.Cu" "B.Cu")
		(net "GND")
	)
	(via
		(at 20.623784 -5.596636)
		(size 0.508)
		(drill 0.254)
		(layers "F.Cu" "B.Cu")
		(net "GND")
	)
	(via
		(at 338.73694 -403.249892)
		(size 0.4572)
		(drill 0.254)
		(layers "F.Cu" "B.Cu")
		(net "GND")
	)
	(via
		(at 372.377462 -277.522432)
		(size 0.4572)
		(drill 0.2032)
		(layers "F.Cu" "B.Cu")
		(net "GND")
	)
	(via
		(at 357.340662 -272.639282)
		(size 0.4572)
		(drill 0.2032)
		(layers "F.Cu" "B.Cu")
		(net "GND")
	)
	(via
		(at 443.367414 -206.666592)
		(size 0.4572)
		(drill 0.2032)
		(layers "F.Cu" "B.Cu")
		(net "GND")
	)
	(via
		(at 63.726314 -271.266666)
		(size 0.4572)
		(drill 0.2032)
		(layers "F.Cu" "B.Cu")
		(net "GND")
	)
	(via
		(at 384.197098 -336.09407)
		(size 0.6604)
		(drill 0.3302)
		(layers "F.Cu" "B.Cu")
		(net "GND")
	)
	(via
		(at 182.549546 -244.916706)
		(size 0.4572)
		(drill 0.2032)
		(layers "F.Cu" "B.Cu")
		(net "GND")
	)
	(via
		(at 277.607014 -217.716608)
		(size 0.4572)
		(drill 0.2032)
		(layers "F.Cu" "B.Cu")
		(net "GND")
	)
	(via
		(at 44.754546 -258.516628)
		(size 0.4572)
		(drill 0.2032)
		(layers "F.Cu" "B.Cu")
		(net "GND")
	)
	(via
		(at 422.945814 -229.616762)
		(size 0.4572)
		(drill 0.2032)
		(layers "F.Cu" "B.Cu")
		(net "GND")
	)
	(via
		(at 270.063214 -250.016772)
		(size 0.4572)
		(drill 0.2032)
		(layers "F.Cu" "B.Cu")
		(net "GND")
	)
	(via
		(at 367.098834 -222.761556)
		(size 0.4572)
		(drill 0.2032)
		(layers "F.Cu" "B.Cu")
		(net "GND")
	)
	(via
		(at 110.700566 -222.761556)
		(size 0.4572)
		(drill 0.2032)
		(layers "F.Cu" "B.Cu")
		(net "GND")
	)
	(via
		(at 453.121014 -313.766708)
		(size 0.4572)
		(drill 0.2032)
		(layers "F.Cu" "B.Cu")
		(net "GND")
	)
	(via
		(at 414.147762 -360.937556)
		(size 0.49022)
		(drill 0.254)
		(layers "F.Cu" "B.Cu")
		(net "GND")
	)
	(via
		(at 88.693498 -181.73319)
		(size 0.508)
		(drill 0.254)
		(layers "F.Cu" "B.Cu")
		(net "GND")
	)
	(via
		(at 277.607014 -313.766708)
		(size 0.4572)
		(drill 0.2032)
		(layers "F.Cu" "B.Cu")
		(net "GND")
	)
	(via
		(at 368.916204 -251.44095)
		(size 0.4572)
		(drill 0.2032)
		(layers "F.Cu" "B.Cu")
		(net "GND")
	)
	(via
		(at 415.708084 -234.716574)
		(size 0.4572)
		(drill 0.2032)
		(layers "F.Cu" "B.Cu")
		(net "GND")
	)
	(via
		(at 429.566832 -12.37488)
		(size 0.508)
		(drill 0.254)
		(layers "F.Cu" "B.Cu")
		(net "GND")
	)
	(via
		(at 419.778942 -410.664152)
		(size 0.4572)
		(drill 0.254)
		(layers "F.Cu" "B.Cu")
		(net "GND")
	)
	(via
		(at 12.69746 -114.072924)
		(size 0.508)
		(drill 0.254)
		(layers "F.Cu" "B.Cu")
		(net "GND")
	)
	(via
		(at 172.795946 -212.616796)
		(size 0.4572)
		(drill 0.2032)
		(layers "F.Cu" "B.Cu")
		(net "GND")
	)
	(via
		(at 379.895862 -280.778204)
		(size 0.4572)
		(drill 0.2032)
		(layers "F.Cu" "B.Cu")
		(net "GND")
	)
	(via
		(at 37.210746 -295.06672)
		(size 0.4572)
		(drill 0.2032)
		(layers "F.Cu" "B.Cu")
		(net "GND")
	)
	(via
		(at 427.045882 -245.76659)
		(size 0.4572)
		(drill 0.2032)
		(layers "F.Cu" "B.Cu")
		(net "GND")
	)
	(via
		(at 343.603834 -247.178322)
		(size 0.4572)
		(drill 0.2032)
		(layers "F.Cu" "B.Cu")
		(net "GND")
	)
	(via
		(at 455.011282 -200.716642)
		(size 0.4572)
		(drill 0.2032)
		(layers "F.Cu" "B.Cu")
		(net "GND")
	)
	(via
		(at 292.694614 -229.616762)
		(size 0.4572)
		(drill 0.2032)
		(layers "F.Cu" "B.Cu")
		(net "GND")
	)
	(via
		(at 66.152014 -301.01667)
		(size 0.4572)
		(drill 0.2032)
		(layers "F.Cu" "B.Cu")
		(net "GND")
	)
	(via
		(at 191.983614 -305.266598)
		(size 0.4572)
		(drill 0.2032)
		(layers "F.Cu" "B.Cu")
		(net "GND")
	)
	(via
		(at 122.448066 -241.481102)
		(size 0.4572)
		(drill 0.2032)
		(layers "F.Cu" "B.Cu")
		(net "GND")
	)
	(via
		(at 121.148094 -289.807142)
		(size 0.4572)
		(drill 0.2032)
		(layers "F.Cu" "B.Cu")
		(net "GND")
	)
	(via
		(at 201.737214 -299.316648)
		(size 0.4572)
		(drill 0.2032)
		(layers "F.Cu" "B.Cu")
		(net "GND")
	)
	(via
		(at 132.785866 -217.064336)
		(size 0.4572)
		(drill 0.2032)
		(layers "F.Cu" "B.Cu")
		(net "GND")
	)
	(via
		(at 73.63968 -63.157608)
		(size 0.508)
		(drill 0.254)
		(layers "F.Cu" "B.Cu")
		(net "GND")
	)
	(via
		(at 43.892978 -345.642438)
		(size 0.508)
		(drill 0.254)
		(layers "F.Cu" "B.Cu")
		(net "GND")
	)
	(via
		(at 382.245616 -275.08073)
		(size 0.4572)
		(drill 0.2032)
		(layers "F.Cu" "B.Cu")
		(net "GND")
	)
	(via
		(at 254.975614 -206.666592)
		(size 0.4572)
		(drill 0.2032)
		(layers "F.Cu" "B.Cu")
		(net "GND")
	)
	(via
		(at 277.607014 -223.666558)
		(size 0.4572)
		(drill 0.2032)
		(layers "F.Cu" "B.Cu")
		(net "GND")
	)
	(via
		(at 175.355504 -116.575586)
		(size 0.4572)
		(drill 0.254)
		(layers "F.Cu" "B.Cu")
		(net "GND")
	)
	(via
		(at 448.074288 -183.009032)
		(size 0.508)
		(drill 0.254)
		(layers "F.Cu" "B.Cu")
		(net "GND")
	)
	(via
		(at 409.748482 -245.76659)
		(size 0.4572)
		(drill 0.2032)
		(layers "F.Cu" "B.Cu")
		(net "GND")
	)
	(via
		(at 21.799804 -107.777026)
		(size 0.508)
		(drill 0.254)
		(layers "F.Cu" "B.Cu")
		(net "GND")
	)
	(via
		(at 419.502082 -303.566576)
		(size 0.4572)
		(drill 0.2032)
		(layers "F.Cu" "B.Cu")
		(net "GND")
	)
	(via
		(at 56.049672 -163.101274)
		(size 0.49022)
		(drill 0.254)
		(layers "F.Cu" "B.Cu")
		(net "GND")
	)
	(via
		(at 52.636166 -414.319974)
		(size 0.508)
		(drill 0.254)
		(layers "F.Cu" "B.Cu")
		(net "GND")
	)
	(via
		(at 96.33585 -407.638504)
		(size 0.4572)
		(drill 0.254)
		(layers "F.Cu" "B.Cu")
		(net "GND")
	)
	(via
		(at 18.679414 -249.166634)
		(size 0.4572)
		(drill 0.2032)
		(layers "F.Cu" "B.Cu")
		(net "GND")
	)
	(via
		(at 138.534648 -280.778204)
		(size 0.4572)
		(drill 0.2032)
		(layers "F.Cu" "B.Cu")
		(net "GND")
	)
	(via
		(at 430.558448 -18.235422)
		(size 0.508)
		(drill 0.254)
		(layers "F.Cu" "B.Cu")
		(net "GND")
	)
	(via
		(at 374.147334 -238.225584)
		(size 0.4572)
		(drill 0.2032)
		(layers "F.Cu" "B.Cu")
		(net "GND")
	)
	(via
		(at 172.795946 -311.216802)
		(size 0.4572)
		(drill 0.2032)
		(layers "F.Cu" "B.Cu")
		(net "GND")
	)
	(via
		(at 412.393638 -406.370536)
		(size 0.4572)
		(drill 0.254)
		(layers "F.Cu" "B.Cu")
		(net "GND")
	)
	(via
		(at 137.124694 -263.686544)
		(size 0.4318)
		(drill 0.2032)
		(layers "F.Cu" "B.Cu")
		(net "GND")
	)
	(via
		(at 117.858794 -275.8948)
		(size 0.4572)
		(drill 0.2032)
		(layers "F.Cu" "B.Cu")
		(net "GND")
	)
	(via
		(at 349.456756 -338.493862)
		(size 0.508)
		(drill 0.254)
		(layers "F.Cu" "B.Cu")
		(net "GND")
	)
	(via
		(at 59.626246 -208.366614)
		(size 0.4572)
		(drill 0.2032)
		(layers "F.Cu" "B.Cu")
		(net "GND")
	)
	(via
		(at 445.53886 -4.140708)
		(size 0.508)
		(drill 0.254)
		(layers "F.Cu" "B.Cu")
		(net "GND")
	)
	(via
		(at 340.250018 -433.899564)
		(size 0.4572)
		(drill 0.2032)
		(layers "F.Cu" "B.Cu")
		(net "GND")
	)
	(via
		(at 359.8672 -397.474948)
		(size 0.508)
		(drill 0.254)
		(layers "F.Cu" "B.Cu")
		(net "GND")
	)
	(via
		(at 453.121014 -250.016772)
		(size 0.4572)
		(drill 0.2032)
		(layers "F.Cu" "B.Cu")
		(net "GND")
	)
	(via
		(at 100.03282 -15.763748)
		(size 0.508)
		(drill 0.254)
		(layers "F.Cu" "B.Cu")
		(net "GND")
	)
	(via
		(at 375.667016 -273.453098)
		(size 0.4572)
		(drill 0.2032)
		(layers "F.Cu" "B.Cu")
		(net "GND")
	)
	(via
		(at 277.607014 -270.416782)
		(size 0.4572)
		(drill 0.2032)
		(layers "F.Cu" "B.Cu")
		(net "GND")
	)
	(via
		(at 171.562014 -205.816708)
		(size 0.4572)
		(drill 0.2032)
		(layers "F.Cu" "B.Cu")
		(net "GND")
	)
	(via
		(at 26.496772 -407.33726)
		(size 0.508)
		(drill 0.254)
		(layers "F.Cu" "B.Cu")
		(net "GND")
	)
	(via
		(at 127.703834 -403.883876)
		(size 0.4064)
		(drill 0.2032)
		(layers "F.Cu" "B.Cu")
		(net "GND")
	)
	(via
		(at 268.829282 -202.416664)
		(size 0.4572)
		(drill 0.2032)
		(layers "F.Cu" "B.Cu")
		(net "GND")
	)
	(via
		(at 301.342044 -359.482898)
		(size 0.508)
		(drill 0.254)
		(layers "F.Cu" "B.Cu")
		(net "GND")
	)
	(via
		(at 29.666946 -234.716574)
		(size 0.4572)
		(drill 0.2032)
		(layers "F.Cu" "B.Cu")
		(net "GND")
	)
	(via
		(at 291.653722 -360.102404)
		(size 0.508)
		(drill 0.254)
		(layers "F.Cu" "B.Cu")
		(net "GND")
	)
	(via
		(at 310.207914 -236.416596)
		(size 0.4572)
		(drill 0.2032)
		(layers "F.Cu" "B.Cu")
		(net "GND")
	)
	(via
		(at 422.55186 -360.074972)
		(size 0.508)
		(drill 0.254)
		(layers "F.Cu" "B.Cu")
		(net "GND")
	)
	(via
		(at 345.593162 -266.941808)
		(size 0.4572)
		(drill 0.2032)
		(layers "F.Cu" "B.Cu")
		(net "GND")
	)
	(via
		(at 190.093346 -208.366614)
		(size 0.4572)
		(drill 0.2032)
		(layers "F.Cu" "B.Cu")
		(net "GND")
	)
	(via
		(at 400.140678 -410.664152)
		(size 0.4572)
		(drill 0.254)
		(layers "F.Cu" "B.Cu")
		(net "GND")
	)
	(via
		(at 125.377194 -287.28924)
		(size 0.4572)
		(drill 0.2032)
		(layers "F.Cu" "B.Cu")
		(net "GND")
	)
	(via
		(at 176.896014 -215.166702)
		(size 0.4572)
		(drill 0.2032)
		(layers "F.Cu" "B.Cu")
		(net "GND")
	)
	(via
		(at 368.542824 -334.282034)
		(size 0.49022)
		(drill 0.254)
		(layers "F.Cu" "B.Cu")
		(net "GND")
	)
	(via
		(at 125.377448 -277.522432)
		(size 0.4572)
		(drill 0.2032)
		(layers "F.Cu" "B.Cu")
		(net "GND")
	)
	(via
		(at 463.171032 -40.352472)
		(size 0.508)
		(drill 0.254)
		(layers "F.Cu" "B.Cu")
		(net "GND")
	)
	(via
		(at 351.579942 -295.033446)
		(size 0.508)
		(drill 0.254)
		(layers "F.Cu" "B.Cu")
		(net "GND")
	)
	(via
		(at 28.433014 -198.166736)
		(size 0.4572)
		(drill 0.2032)
		(layers "F.Cu" "B.Cu")
		(net "GND")
	)
	(via
		(at 209.281014 -275.516594)
		(size 0.4572)
		(drill 0.2032)
		(layers "F.Cu" "B.Cu")
		(net "GND")
	)
	(via
		(at 57.404762 -160.22828)
		(size 0.508)
		(drill 0.254)
		(layers "F.Cu" "B.Cu")
		(net "GND")
	)
	(via
		(at 430.489614 -214.316564)
		(size 0.4572)
		(drill 0.2032)
		(layers "F.Cu" "B.Cu")
		(net "GND")
	)
	(via
		(at 59.842146 -301.866808)
		(size 0.4572)
		(drill 0.2032)
		(layers "F.Cu" "B.Cu")
		(net "GND")
	)
	(via
		(at 87.484966 -335.187036)
		(size 0.49022)
		(drill 0.254)
		(layers "F.Cu" "B.Cu")
		(net "GND")
	)
	(via
		(at 195.427346 -236.416596)
		(size 0.4572)
		(drill 0.2032)
		(layers "F.Cu" "B.Cu")
		(net "GND")
	)
	(via
		(at 281.707082 -245.76659)
		(size 0.4572)
		(drill 0.2032)
		(layers "F.Cu" "B.Cu")
		(net "GND")
	)
	(via
		(at 126.570486 -330.214732)
		(size 0.508)
		(drill 0.254)
		(layers "F.Cu" "B.Cu")
		(net "GND")
	)
	(via
		(at 447.141092 -72.097392)
		(size 0.508)
		(drill 0.254)
		(layers "F.Cu" "B.Cu")
		(net "GND")
	)
	(via
		(at 422.945814 -268.71676)
		(size 0.4572)
		(drill 0.2032)
		(layers "F.Cu" "B.Cu")
		(net "GND")
	)
	(via
		(at 112.710976 -109.106462)
		(size 0.508)
		(drill 0.254)
		(layers "F.Cu" "B.Cu")
		(net "GND")
	)
	(via
		(at 381.673862 -403.249892)
		(size 0.4572)
		(drill 0.254)
		(layers "F.Cu" "B.Cu")
		(net "GND")
	)
	(via
		(at 139.510516 -254.164592)
		(size 0.4572)
		(drill 0.2032)
		(layers "F.Cu" "B.Cu")
		(net "GND")
	)
	(via
		(at 273.62658 -93.741494)
		(size 0.508)
		(drill 0.254)
		(layers "F.Cu" "B.Cu")
		(net "GND")
	)
	(via
		(at 124.327412 -238.225584)
		(size 0.4572)
		(drill 0.2032)
		(layers "F.Cu" "B.Cu")
		(net "GND")
	)
	(via
		(at 113.274856 -79.815436)
		(size 0.508)
		(drill 0.254)
		(layers "F.Cu" "B.Cu")
		(net "GND")
	)
	(via
		(at 426.505624 -19.759422)
		(size 0.508)
		(drill 0.254)
		(layers "F.Cu" "B.Cu")
		(net "GND")
	)
	(via
		(at 285.150814 -234.716574)
		(size 0.4572)
		(drill 0.2032)
		(layers "F.Cu" "B.Cu")
		(net "GND")
	)
	(via
		(at 65.70345 -409.396184)
		(size 0.4572)
		(drill 0.254)
		(layers "F.Cu" "B.Cu")
		(net "GND")
	)
	(via
		(at 87.315294 -262.058658)
		(size 0.4318)
		(drill 0.2032)
		(layers "F.Cu" "B.Cu")
		(net "GND")
	)
	(via
		(at 345.953334 -243.108988)
		(size 0.4572)
		(drill 0.2032)
		(layers "F.Cu" "B.Cu")
		(net "GND")
	)
	(via
		(at 51.743864 -5.596636)
		(size 0.508)
		(drill 0.254)
		(layers "F.Cu" "B.Cu")
		(net "GND")
	)
	(via
		(at 386.350002 -430.299622)
		(size 0.4572)
		(drill 0.2032)
		(layers "F.Cu" "B.Cu")
		(net "GND")
	)
	(via
		(at 419.502082 -205.816708)
		(size 0.4572)
		(drill 0.2032)
		(layers "F.Cu" "B.Cu")
		(net "GND")
	)
	(via
		(at 125.267466 -249.620024)
		(size 0.4572)
		(drill 0.2032)
		(layers "F.Cu" "B.Cu")
		(net "GND")
	)
	(via
		(at 294.617648 -162.106864)
		(size 0.508)
		(drill 0.254)
		(layers "F.Cu" "B.Cu")
		(net "GND")
	)
	(via
		(at 144.463262 -400.224244)
		(size 0.4572)
		(drill 0.254)
		(layers "F.Cu" "B.Cu")
		(net "GND")
	)
	(via
		(at 374.257316 -274.266914)
		(size 0.4572)
		(drill 0.2032)
		(layers "F.Cu" "B.Cu")
		(net "GND")
	)
	(via
		(at 410.35732 -175.707548)
		(size 0.508)
		(drill 0.254)
		(layers "F.Cu" "B.Cu")
		(net "GND")
	)
	(via
		(at 136.075166 -224.389442)
		(size 0.4572)
		(drill 0.2032)
		(layers "F.Cu" "B.Cu")
		(net "GND")
	)
	(via
		(at 369.558316 -274.266914)
		(size 0.4572)
		(drill 0.2032)
		(layers "F.Cu" "B.Cu")
		(net "GND")
	)
	(via
		(at 419.502082 -308.666642)
		(size 0.4572)
		(drill 0.2032)
		(layers "F.Cu" "B.Cu")
		(net "GND")
	)
	(via
		(at 14.579346 -225.36658)
		(size 0.4572)
		(drill 0.2032)
		(layers "F.Cu" "B.Cu")
		(net "GND")
	)
	(via
		(at 179.105814 -272.966688)
		(size 0.4572)
		(drill 0.2032)
		(layers "F.Cu" "B.Cu")
		(net "GND")
	)
	(via
		(at 118.798594 -284.033722)
		(size 0.4572)
		(drill 0.2032)
		(layers "F.Cu" "B.Cu")
		(net "GND")
	)
	(via
		(at 352.172016 -278.336502)
		(size 0.4572)
		(drill 0.2032)
		(layers "F.Cu" "B.Cu")
		(net "GND")
	)
	(via
		(at 92.501466 -100.227384)
		(size 0.508)
		(drill 0.254)
		(layers "F.Cu" "B.Cu")
		(net "GND")
	)
	(via
		(at 409.748482 -277.216616)
		(size 0.4572)
		(drill 0.2032)
		(layers "F.Cu" "B.Cu")
		(net "GND")
	)
	(via
		(at 438.033414 -283.166566)
		(size 0.4572)
		(drill 0.2032)
		(layers "F.Cu" "B.Cu")
		(net "GND")
	)
	(via
		(at 190.093346 -238.966756)
		(size 0.4572)
		(drill 0.2032)
		(layers "F.Cu" "B.Cu")
		(net "GND")
	)
	(via
		(at 46.964346 -285.716726)
		(size 0.4572)
		(drill 0.2032)
		(layers "F.Cu" "B.Cu")
		(net "GND")
	)
	(via
		(at 191.983614 -269.566644)
		(size 0.4572)
		(drill 0.2032)
		(layers "F.Cu" "B.Cu")
		(net "GND")
	)
	(via
		(at 33.767014 -261.066788)
		(size 0.4572)
		(drill 0.2032)
		(layers "F.Cu" "B.Cu")
		(net "GND")
	)
	(via
		(at 423.195242 -394.603478)
		(size 0.508)
		(drill 0.254)
		(layers "F.Cu" "B.Cu")
		(net "GND")
	)
	(via
		(at 424.836082 -282.316682)
		(size 0.4572)
		(drill 0.2032)
		(layers "F.Cu" "B.Cu")
		(net "GND")
	)
	(via
		(at 412.18358 -175.707548)
		(size 0.508)
		(drill 0.254)
		(layers "F.Cu" "B.Cu")
		(net "GND")
	)
	(via
		(at 417.089082 -275.516594)
		(size 0.4572)
		(drill 0.2032)
		(layers "F.Cu" "B.Cu")
		(net "GND")
	)
	(via
		(at 127.342646 -400.224244)
		(size 0.4572)
		(drill 0.254)
		(layers "F.Cu" "B.Cu")
		(net "GND")
	)
	(via
		(at 357.810562 -266.941808)
		(size 0.4572)
		(drill 0.2032)
		(layers "F.Cu" "B.Cu")
		(net "GND")
	)
	(via
		(at 169.352214 -305.266598)
		(size 0.4572)
		(drill 0.2032)
		(layers "F.Cu" "B.Cu")
		(net "GND")
	)
	(via
		(at 344.363294 -41.401492)
		(size 0.4572)
		(drill 0.2032)
		(layers "F.Cu" "B.Cu")
		(net "GND")
	)
	(via
		(at 396.349982 -433.747164)
		(size 0.4572)
		(drill 0.2032)
		(layers "F.Cu" "B.Cu")
		(net "GND")
	)
	(via
		(at 430.7713 -24.494998)
		(size 0.508)
		(drill 0.254)
		(layers "F.Cu" "B.Cu")
		(net "GND")
	)
	(via
		(at 101.617018 -331.703426)
		(size 0.508)
		(drill 0.254)
		(layers "F.Cu" "B.Cu")
		(net "GND")
	)
	(via
		(at 341.834216 -275.08073)
		(size 0.4572)
		(drill 0.2032)
		(layers "F.Cu" "B.Cu")
		(net "GND")
	)
	(via
		(at 68.661788 -188.012578)
		(size 0.508)
		(drill 0.254)
		(layers "F.Cu" "B.Cu")
		(net "GND")
	)
	(via
		(at 376.96648 -243.108988)
		(size 0.4572)
		(drill 0.2032)
		(layers "F.Cu" "B.Cu")
		(net "GND")
	)
	(via
		(at 21.790152 -60.999878)
		(size 0.508)
		(drill 0.254)
		(layers "F.Cu" "B.Cu")
		(net "GND")
	)
	(via
		(at 388.607808 -338.964016)
		(size 0.508)
		(drill 0.254)
		(layers "F.Cu" "B.Cu")
		(net "GND")
	)
	(via
		(at 336.195162 -273.453098)
		(size 0.4572)
		(drill 0.2032)
		(layers "F.Cu" "B.Cu")
		(net "GND")
	)
	(via
		(at 386.474462 -284.033722)
		(size 0.4572)
		(drill 0.2032)
		(layers "F.Cu" "B.Cu")
		(net "GND")
	)
	(via
		(at 279.816814 -268.71676)
		(size 0.4572)
		(drill 0.2032)
		(layers "F.Cu" "B.Cu")
		(net "GND")
	)
	(via
		(at 11.135614 -233.86669)
		(size 0.4572)
		(drill 0.2032)
		(layers "F.Cu" "B.Cu")
		(net "GND")
	)
	(via
		(at 74.89317 -409.396184)
		(size 0.4572)
		(drill 0.254)
		(layers "F.Cu" "B.Cu")
		(net "GND")
	)
	(via
		(at 350.716088 -407.00452)
		(size 0.4064)
		(drill 0.2032)
		(layers "F.Cu" "B.Cu")
		(net "GND")
	)
	(via
		(at 407.525982 -410.664152)
		(size 0.4572)
		(drill 0.254)
		(layers "F.Cu" "B.Cu")
		(net "GND")
	)
	(via
		(at 345.15171 -45.350176)
		(size 0.4572)
		(drill 0.2032)
		(layers "F.Cu" "B.Cu")
		(net "GND")
	)
	(via
		(at 368.97818 -234.15625)
		(size 0.4572)
		(drill 0.2032)
		(layers "F.Cu" "B.Cu")
		(net "GND")
	)
	(via
		(at 342.664034 -245.55069)
		(size 0.4572)
		(drill 0.2032)
		(layers "F.Cu" "B.Cu")
		(net "GND")
	)
	(via
		(at 172.795946 -273.816572)
		(size 0.4572)
		(drill 0.2032)
		(layers "F.Cu" "B.Cu")
		(net "GND")
	)
	(via
		(at 164.018214 -289.966654)
		(size 0.4572)
		(drill 0.2032)
		(layers "F.Cu" "B.Cu")
		(net "GND")
	)
	(via
		(at 113.269776 -91.199462)
		(size 0.508)
		(drill 0.254)
		(layers "F.Cu" "B.Cu")
		(net "GND")
	)
	(via
		(at 443.367414 -216.016586)
		(size 0.4572)
		(drill 0.2032)
		(layers "F.Cu" "B.Cu")
		(net "GND")
	)
	(via
		(at 128.35001 -434.899562)
		(size 0.4572)
		(drill 0.2032)
		(layers "F.Cu" "B.Cu")
		(net "GND")
	)
	(via
		(at 321.250056 -433.747164)
		(size 0.4572)
		(drill 0.2032)
		(layers "F.Cu" "B.Cu")
		(net "GND")
	)
	(via
		(at 2.764536 -381.430022)
		(size 0.508)
		(drill 0.254)
		(layers "F.Cu" "B.Cu")
		(net "GND")
	)
	(via
		(at 411.958282 -247.466612)
		(size 0.4572)
		(drill 0.2032)
		(layers "F.Cu" "B.Cu")
		(net "GND")
	)
	(via
		(at 90.604594 -279.150318)
		(size 0.4572)
		(drill 0.2032)
		(layers "F.Cu" "B.Cu")
		(net "GND")
	)
	(via
		(at 207.071214 -267.866622)
		(size 0.4572)
		(drill 0.2032)
		(layers "F.Cu" "B.Cu")
		(net "GND")
	)
	(via
		(at 264.729214 -199.01662)
		(size 0.4572)
		(drill 0.2032)
		(layers "F.Cu" "B.Cu")
		(net "GND")
	)
	(via
		(at 205.180946 -311.216802)
		(size 0.4572)
		(drill 0.2032)
		(layers "F.Cu" "B.Cu")
		(net "GND")
	)
	(via
		(at 58.591958 -400.858228)
		(size 0.4064)
		(drill 0.2032)
		(layers "F.Cu" "B.Cu")
		(net "GND")
	)
	(via
		(at 334.785462 -259.616956)
		(size 0.4318)
		(drill 0.2032)
		(layers "F.Cu" "B.Cu")
		(net "GND")
	)
	(via
		(at 98.593148 -279.964134)
		(size 0.4572)
		(drill 0.2032)
		(layers "F.Cu" "B.Cu")
		(net "GND")
	)
	(via
		(at 16.789146 -276.366732)
		(size 0.4572)
		(drill 0.2032)
		(layers "F.Cu" "B.Cu")
		(net "GND")
	)
	(via
		(at 182.549546 -273.816572)
		(size 0.4572)
		(drill 0.2032)
		(layers "F.Cu" "B.Cu")
		(net "GND")
	)
	(via
		(at 182.675276 -46.966886)
		(size 0.508)
		(drill 0.254)
		(layers "F.Cu" "B.Cu")
		(net "GND")
	)
	(via
		(at 179.105814 -198.166736)
		(size 0.4572)
		(drill 0.2032)
		(layers "F.Cu" "B.Cu")
		(net "GND")
	)
	(via
		(at 20.63115 -181.826916)
		(size 0.508)
		(drill 0.254)
		(layers "F.Cu" "B.Cu")
		(net "GND")
	)
	(via
		(at 52.298346 -306.116736)
		(size 0.4572)
		(drill 0.2032)
		(layers "F.Cu" "B.Cu")
		(net "GND")
	)
	(via
		(at 216.824814 -286.56661)
		(size 0.4572)
		(drill 0.2032)
		(layers "F.Cu" "B.Cu")
		(net "GND")
	)
	(via
		(at 455.011282 -308.666642)
		(size 0.4572)
		(drill 0.2032)
		(layers "F.Cu" "B.Cu")
		(net "GND")
	)
	(via
		(at 309.908956 -404.51786)
		(size 0.4572)
		(drill 0.254)
		(layers "F.Cu" "B.Cu")
		(net "GND")
	)
	(via
		(at 54.508146 -248.31675)
		(size 0.4572)
		(drill 0.2032)
		(layers "F.Cu" "B.Cu")
		(net "GND")
	)
	(via
		(at 378.956062 -274.266914)
		(size 0.4572)
		(drill 0.2032)
		(layers "F.Cu" "B.Cu")
		(net "GND")
	)
	(via
		(at 48.854614 -262.76681)
		(size 0.4572)
		(drill 0.2032)
		(layers "F.Cu" "B.Cu")
		(net "GND")
	)
	(via
		(at 202.971146 -210.916774)
		(size 0.4572)
		(drill 0.2032)
		(layers "F.Cu" "B.Cu")
		(net "GND")
	)
	(via
		(at 373.207534 -249.620024)
		(size 0.4572)
		(drill 0.2032)
		(layers "F.Cu" "B.Cu")
		(net "GND")
	)
	(via
		(at 311.882282 -224.516696)
		(size 0.4572)
		(drill 0.2032)
		(layers "F.Cu" "B.Cu")
		(net "GND")
	)
	(via
		(at 343.891108 -73.03516)
		(size 0.508)
		(drill 0.254)
		(layers "F.Cu" "B.Cu")
		(net "GND")
	)
	(via
		(at 377.546616 -276.708616)
		(size 0.4572)
		(drill 0.2032)
		(layers "F.Cu" "B.Cu")
		(net "GND")
	)
	(via
		(at 270.063214 -258.516628)
		(size 0.4572)
		(drill 0.2032)
		(layers "F.Cu" "B.Cu")
		(net "GND")
	)
	(via
		(at 464.764882 -198.166736)
		(size 0.4572)
		(drill 0.2032)
		(layers "F.Cu" "B.Cu")
		(net "GND")
	)
	(via
		(at 311.882282 -202.416664)
		(size 0.4572)
		(drill 0.2032)
		(layers "F.Cu" "B.Cu")
		(net "GND")
	)
	(via
		(at 67.507866 -410.664152)
		(size 0.4572)
		(drill 0.254)
		(layers "F.Cu" "B.Cu")
		(net "GND")
	)
	(via
		(at 354.051616 -279.964134)
		(size 0.4572)
		(drill 0.2032)
		(layers "F.Cu" "B.Cu")
		(net "GND")
	)
	(via
		(at 11.135614 -198.166736)
		(size 0.4572)
		(drill 0.2032)
		(layers "F.Cu" "B.Cu")
		(net "GND")
	)
	(via
		(at 436.18912 -44.44238)
		(size 0.508)
		(drill 0.254)
		(layers "F.Cu" "B.Cu")
		(net "GND")
	)
	(via
		(at 56.930798 -359.24363)
		(size 0.508)
		(drill 0.254)
		(layers "F.Cu" "B.Cu")
		(net "GND")
	)
	(via
		(at 445.577214 -203.266802)
		(size 0.4572)
		(drill 0.2032)
		(layers "F.Cu" "B.Cu")
		(net "GND")
	)
	(via
		(at 39.420546 -295.06672)
		(size 0.4572)
		(drill 0.2032)
		(layers "F.Cu" "B.Cu")
		(net "GND")
	)
	(via
		(at 113.629694 -273.453098)
		(size 0.4572)
		(drill 0.2032)
		(layers "F.Cu" "B.Cu")
		(net "GND")
	)
	(via
		(at 76.336398 -407.00452)
		(size 0.4064)
		(drill 0.2032)
		(layers "F.Cu" "B.Cu")
		(net "GND")
	)
	(via
		(at 172.795946 -244.916706)
		(size 0.4572)
		(drill 0.2032)
		(layers "F.Cu" "B.Cu")
		(net "GND")
	)
	(via
		(at 376.966734 -217.064336)
		(size 0.4572)
		(drill 0.2032)
		(layers "F.Cu" "B.Cu")
		(net "GND")
	)
	(via
		(at 29.666946 -270.416782)
		(size 0.4572)
		(drill 0.2032)
		(layers "F.Cu" "B.Cu")
		(net "GND")
	)
	(via
		(at 124.005594 -410.030168)
		(size 0.4064)
		(drill 0.2032)
		(layers "F.Cu" "B.Cu")
		(net "GND")
	)
	(via
		(at 230.984044 -51.564794)
		(size 0.508)
		(drill 0.254)
		(layers "F.Cu" "B.Cu")
		(net "GND")
	)
	(via
		(at 202.02398 -120.614948)
		(size 0.508)
		(drill 0.254)
		(layers "F.Cu" "B.Cu")
		(net "GND")
	)
	(via
		(at 274.163282 -267.866622)
		(size 0.4572)
		(drill 0.2032)
		(layers "F.Cu" "B.Cu")
		(net "GND")
	)
	(via
		(at 411.349952 -431.451258)
		(size 0.4572)
		(drill 0.2032)
		(layers "F.Cu" "B.Cu")
		(net "GND")
	)
	(via
		(at 179.105814 -264.466578)
		(size 0.4572)
		(drill 0.2032)
		(layers "F.Cu" "B.Cu")
		(net "GND")
	)
	(via
		(at 357.533702 -44.998386)
		(size 0.508)
		(drill 0.254)
		(layers "F.Cu" "B.Cu")
		(net "GND")
	)
	(via
		(at 29.666946 -311.216802)
		(size 0.4572)
		(drill 0.2032)
		(layers "F.Cu" "B.Cu")
		(net "GND")
	)
	(via
		(at 404.462742 -410.664152)
		(size 0.4572)
		(drill 0.254)
		(layers "F.Cu" "B.Cu")
		(net "GND")
	)
	(via
		(at 130.350006 -436.347362)
		(size 0.4572)
		(drill 0.2032)
		(layers "F.Cu" "B.Cu")
		(net "GND")
	)
	(via
		(at 172.795946 -260.21665)
		(size 0.4572)
		(drill 0.2032)
		(layers "F.Cu" "B.Cu")
		(net "GND")
	)
	(via
		(at 157.708346 -231.316784)
		(size 0.4572)
		(drill 0.2032)
		(layers "F.Cu" "B.Cu")
		(net "GND")
	)
	(via
		(at 132.315966 -243.922804)
		(size 0.4572)
		(drill 0.2032)
		(layers "F.Cu" "B.Cu")
		(net "GND")
	)
	(via
		(at 50.748438 -407.00452)
		(size 0.4064)
		(drill 0.2032)
		(layers "F.Cu" "B.Cu")
		(net "GND")
	)
	(via
		(at 92.365322 -331.852524)
		(size 0.508)
		(drill 0.254)
		(layers "F.Cu" "B.Cu")
		(net "GND")
	)
	(via
		(at 407.858214 -208.366614)
		(size 0.4572)
		(drill 0.2032)
		(layers "F.Cu" "B.Cu")
		(net "GND")
	)
	(via
		(at 417.10229 -105.207308)
		(size 0.508)
		(drill 0.254)
		(layers "F.Cu" "B.Cu")
		(net "GND")
	)
	(via
		(at 382.605534 -217.064336)
		(size 0.4572)
		(drill 0.2032)
		(layers "F.Cu" "B.Cu")
		(net "GND")
	)
	(via
		(at 304.122582 -207.51673)
		(size 0.4572)
		(drill 0.2032)
		(layers "F.Cu" "B.Cu")
		(net "GND")
	)
	(via
		(at 445.577214 -276.366732)
		(size 0.4572)
		(drill 0.2032)
		(layers "F.Cu" "B.Cu")
		(net "GND")
	)
	(via
		(at 130.350006 -427.851316)
		(size 0.4572)
		(drill 0.2032)
		(layers "F.Cu" "B.Cu")
		(net "GND")
	)
	(via
		(at 321.250056 -438.499758)
		(size 0.4572)
		(drill 0.2032)
		(layers "F.Cu" "B.Cu")
		(net "GND")
	)
	(via
		(at 276.373082 -205.816708)
		(size 0.4572)
		(drill 0.2032)
		(layers "F.Cu" "B.Cu")
		(net "GND")
	)
	(via
		(at 135.273542 -404.51786)
		(size 0.4572)
		(drill 0.254)
		(layers "F.Cu" "B.Cu")
		(net "GND")
	)
	(via
		(at 194.193414 -228.766624)
		(size 0.4572)
		(drill 0.2032)
		(layers "F.Cu" "B.Cu")
		(net "GND")
	)
	(via
		(at 207.071214 -198.166736)
		(size 0.4572)
		(drill 0.2032)
		(layers "F.Cu" "B.Cu")
		(net "GND")
	)
	(via
		(at 409.748482 -291.666676)
		(size 0.4572)
		(drill 0.2032)
		(layers "F.Cu" "B.Cu")
		(net "GND")
	)
	(via
		(at 22.123146 -236.416596)
		(size 0.4572)
		(drill 0.2032)
		(layers "F.Cu" "B.Cu")
		(net "GND")
	)
	(via
		(at 184.439814 -271.266666)
		(size 0.4572)
		(drill 0.2032)
		(layers "F.Cu" "B.Cu")
		(net "GND")
	)
	(via
		(at 387.414516 -262.872474)
		(size 0.4572)
		(drill 0.2032)
		(layers "F.Cu" "B.Cu")
		(net "GND")
	)
	(via
		(at 176.238154 -352.074988)
		(size 0.508)
		(drill 0.254)
		(layers "F.Cu" "B.Cu")
		(net "GND")
	)
	(via
		(at 47.782226 -404.51786)
		(size 0.4572)
		(drill 0.254)
		(layers "F.Cu" "B.Cu")
		(net "GND")
	)
	(via
		(at 152.985724 -36.341558)
		(size 0.508)
		(drill 0.254)
		(layers "F.Cu" "B.Cu")
		(net "GND")
	)
	(via
		(at 332.696312 -56.908446)
		(size 0.4572)
		(drill 0.2032)
		(layers "F.Cu" "B.Cu")
		(net "GND")
	)
	(via
		(at 341.367872 -330.347066)
		(size 0.508)
		(drill 0.254)
		(layers "F.Cu" "B.Cu")
		(net "GND")
	)
	(via
		(at 336.250026 -431.451258)
		(size 0.4572)
		(drill 0.2032)
		(layers "F.Cu" "B.Cu")
		(net "GND")
	)
	(via
		(at 386.474462 -285.661354)
		(size 0.4572)
		(drill 0.2032)
		(layers "F.Cu" "B.Cu")
		(net "GND")
	)
	(via
		(at 180.339746 -315.46673)
		(size 0.4572)
		(drill 0.2032)
		(layers "F.Cu" "B.Cu")
		(net "GND")
	)
	(via
		(at 368.50828 -233.34218)
		(size 0.4572)
		(drill 0.2032)
		(layers "F.Cu" "B.Cu")
		(net "GND")
	)
	(via
		(at 186.649614 -228.766624)
		(size 0.4572)
		(drill 0.2032)
		(layers "F.Cu" "B.Cu")
		(net "GND")
	)
	(via
		(at 42.046906 -19.770344)
		(size 0.508)
		(drill 0.254)
		(layers "F.Cu" "B.Cu")
		(net "GND")
	)
	(via
		(at 311.16778 -404.51786)
		(size 0.4572)
		(drill 0.254)
		(layers "F.Cu" "B.Cu")
		(net "GND")
	)
	(via
		(at 125.377194 -280.778204)
		(size 0.4572)
		(drill 0.2032)
		(layers "F.Cu" "B.Cu")
		(net "GND")
	)
	(via
		(at 87.785194 -284.033722)
		(size 0.4572)
		(drill 0.2032)
		(layers "F.Cu" "B.Cu")
		(net "GND")
	)
	(via
		(at 419.502082 -249.166634)
		(size 0.4572)
		(drill 0.2032)
		(layers "F.Cu" "B.Cu")
		(net "GND")
	)
	(via
		(at 460.664814 -296.766742)
		(size 0.4572)
		(drill 0.2032)
		(layers "F.Cu" "B.Cu")
		(net "GND")
	)
	(via
		(at 7.035546 -233.016806)
		(size 0.4572)
		(drill 0.2032)
		(layers "F.Cu" "B.Cu")
		(net "GND")
	)
	(via
		(at 26.961084 -323.434456)
		(size 0.4572)
		(drill 0.2032)
		(layers "F.Cu" "B.Cu")
		(net "GND")
	)
	(via
		(at 161.808414 -264.466578)
		(size 0.4572)
		(drill 0.2032)
		(layers "F.Cu" "B.Cu")
		(net "GND")
	)
	(via
		(at 291.460682 -244.066568)
		(size 0.4572)
		(drill 0.2032)
		(layers "F.Cu" "B.Cu")
		(net "GND")
	)
	(via
		(at 247.975882 -135.693404)
		(size 0.508)
		(drill 0.254)
		(layers "F.Cu" "B.Cu")
		(net "GND")
	)
	(via
		(at 405.4348 -217.716608)
		(size 0.4572)
		(drill 0.2032)
		(layers "F.Cu" "B.Cu")
		(net "GND")
	)
	(via
		(at 187.883546 -208.366614)
		(size 0.4572)
		(drill 0.2032)
		(layers "F.Cu" "B.Cu")
		(net "GND")
	)
	(via
		(at 272.273014 -315.46673)
		(size 0.4572)
		(drill 0.2032)
		(layers "F.Cu" "B.Cu")
		(net "GND")
	)
	(via
		(at 202.971146 -304.416714)
		(size 0.4572)
		(drill 0.2032)
		(layers "F.Cu" "B.Cu")
		(net "GND")
	)
	(via
		(at 41.310814 -232.166668)
		(size 0.4572)
		(drill 0.2032)
		(layers "F.Cu" "B.Cu")
		(net "GND")
	)
	(via
		(at 49.901094 -351.608644)
		(size 0.49022)
		(drill 0.254)
		(layers "F.Cu" "B.Cu")
		(net "GND")
	)
	(via
		(at 438.033414 -195.616576)
		(size 0.4572)
		(drill 0.2032)
		(layers "F.Cu" "B.Cu")
		(net "GND")
	)
	(via
		(at 380.72568 -241.481102)
		(size 0.4572)
		(drill 0.2032)
		(layers "F.Cu" "B.Cu")
		(net "GND")
	)
	(via
		(at 95.267526 -326.788272)
		(size 0.508)
		(drill 0.254)
		(layers "F.Cu" "B.Cu")
		(net "GND")
	)
	(via
		(at 31.876746 -231.316784)
		(size 0.4572)
		(drill 0.2032)
		(layers "F.Cu" "B.Cu")
		(net "GND")
	)
	(via
		(at 31.147004 -7.215124)
		(size 0.508)
		(drill 0.254)
		(layers "F.Cu" "B.Cu")
		(net "GND")
	)
	(via
		(at 259.075682 -280.61666)
		(size 0.4572)
		(drill 0.2032)
		(layers "F.Cu" "B.Cu")
		(net "GND")
	)
	(via
		(at 409.748482 -241.516662)
		(size 0.4572)
		(drill 0.2032)
		(layers "F.Cu" "B.Cu")
		(net "GND")
	)
	(via
		(at 374.634506 -185.900568)
		(size 0.508)
		(drill 0.254)
		(layers "F.Cu" "B.Cu")
		(net "GND")
	)
	(via
		(at 172.795946 -229.616762)
		(size 0.4572)
		(drill 0.2032)
		(layers "F.Cu" "B.Cu")
		(net "GND")
	)
	(via
		(at 26.223214 -235.566712)
		(size 0.4572)
		(drill 0.2032)
		(layers "F.Cu" "B.Cu")
		(net "GND")
	)
	(via
		(at 52.911248 -147.59559)
		(size 0.49022)
		(drill 0.254)
		(layers "F.Cu" "B.Cu")
		(net "GND")
	)
	(via
		(at 161.808414 -224.516696)
		(size 0.4572)
		(drill 0.2032)
		(layers "F.Cu" "B.Cu")
		(net "GND")
	)
	(via
		(at 338.544662 -284.033722)
		(size 0.4572)
		(drill 0.2032)
		(layers "F.Cu" "B.Cu")
		(net "GND")
	)
	(via
		(at 184.439814 -261.066788)
		(size 0.4572)
		(drill 0.2032)
		(layers "F.Cu" "B.Cu")
		(net "GND")
	)
	(via
		(at 98.013266 -247.992138)
		(size 0.4572)
		(drill 0.2032)
		(layers "F.Cu" "B.Cu")
		(net "GND")
	)
	(via
		(at 100.942394 -266.128246)
		(size 0.4572)
		(drill 0.2032)
		(layers "F.Cu" "B.Cu")
		(net "GND")
	)
	(via
		(at 449.677282 -247.466612)
		(size 0.4572)
		(drill 0.2032)
		(layers "F.Cu" "B.Cu")
		(net "GND")
	)
	(via
		(at 14.579346 -203.266802)
		(size 0.4572)
		(drill 0.2032)
		(layers "F.Cu" "B.Cu")
		(net "GND")
	)
	(via
		(at 16.789146 -203.266802)
		(size 0.4572)
		(drill 0.2032)
		(layers "F.Cu" "B.Cu")
		(net "GND")
	)
	(via
		(at 85.325712 -222.761556)
		(size 0.4572)
		(drill 0.2032)
		(layers "F.Cu" "B.Cu")
		(net "GND")
	)
	(via
		(at 137.954766 -230.900478)
		(size 0.4318)
		(drill 0.2032)
		(layers "F.Cu" "B.Cu")
		(net "GND")
	)
	(via
		(at 307.782214 -240.666778)
		(size 0.4572)
		(drill 0.2032)
		(layers "F.Cu" "B.Cu")
		(net "GND")
	)
	(via
		(at 325.250048 -428.851314)
		(size 0.4572)
		(drill 0.2032)
		(layers "F.Cu" "B.Cu")
		(net "GND")
	)
	(via
		(at 179.105814 -196.466714)
		(size 0.4572)
		(drill 0.2032)
		(layers "F.Cu" "B.Cu")
		(net "GND")
	)
	(via
		(at 44.754546 -214.316564)
		(size 0.4572)
		(drill 0.2032)
		(layers "F.Cu" "B.Cu")
		(net "GND")
	)
	(via
		(at 389.24357 -400.858228)
		(size 0.4064)
		(drill 0.2032)
		(layers "F.Cu" "B.Cu")
		(net "GND")
	)
	(via
		(at 212.724746 -278.066754)
		(size 0.4572)
		(drill 0.2032)
		(layers "F.Cu" "B.Cu")
		(net "GND")
	)
	(via
		(at 467.535514 -129.40538)
		(size 0.508)
		(drill 0.254)
		(layers "F.Cu" "B.Cu")
		(net "GND")
	)
	(via
		(at 414.070292 -161.556954)
		(size 0.49022)
		(drill 0.254)
		(layers "F.Cu" "B.Cu")
		(net "GND")
	)
	(via
		(at 381.305562 -270.19758)
		(size 0.4572)
		(drill 0.2032)
		(layers "F.Cu" "B.Cu")
		(net "GND")
	)
	(via
		(at 351.122234 -222.761556)
		(size 0.4572)
		(drill 0.2032)
		(layers "F.Cu" "B.Cu")
		(net "GND")
	)
	(via
		(at 50.612294 -353.187)
		(size 0.49022)
		(drill 0.254)
		(layers "F.Cu" "B.Cu")
		(net "GND")
	)
	(via
		(at 49.04105 -404.51786)
		(size 0.4572)
		(drill 0.254)
		(layers "F.Cu" "B.Cu")
		(net "GND")
	)
	(via
		(at 438.033414 -234.716574)
		(size 0.4572)
		(drill 0.2032)
		(layers "F.Cu" "B.Cu")
		(net "GND")
	)
	(via
		(at 33.767014 -238.116618)
		(size 0.4572)
		(drill 0.2032)
		(layers "F.Cu" "B.Cu")
		(net "GND")
	)
	(via
		(at 16.994124 -407.23312)
		(size 0.508)
		(drill 0.254)
		(layers "F.Cu" "B.Cu")
		(net "GND")
	)
	(via
		(at 137.594594 -282.405836)
		(size 0.4572)
		(drill 0.2032)
		(layers "F.Cu" "B.Cu")
		(net "GND")
	)
	(via
		(at 430.489614 -246.616728)
		(size 0.4572)
		(drill 0.2032)
		(layers "F.Cu" "B.Cu")
		(net "GND")
	)
	(via
		(at 105.171748 -288.103056)
		(size 0.4572)
		(drill 0.2032)
		(layers "F.Cu" "B.Cu")
		(net "GND")
	)
	(via
		(at 165.252146 -260.21665)
		(size 0.4572)
		(drill 0.2032)
		(layers "F.Cu" "B.Cu")
		(net "GND")
	)
	(via
		(at 372.377462 -256.361438)
		(size 0.4572)
		(drill 0.2032)
		(layers "F.Cu" "B.Cu")
		(net "GND")
	)
	(via
		(at 268.829282 -233.86669)
		(size 0.4572)
		(drill 0.2032)
		(layers "F.Cu" "B.Cu")
		(net "GND")
	)
	(via
		(at 421.23106 -360.735372)
		(size 0.508)
		(drill 0.254)
		(layers "F.Cu" "B.Cu")
		(net "GND")
	)
	(via
		(at 384.494786 -66.973704)
		(size 0.508)
		(drill 0.254)
		(layers "F.Cu" "B.Cu")
		(net "GND")
	)
	(via
		(at 287.360614 -221.96679)
		(size 0.4572)
		(drill 0.2032)
		(layers "F.Cu" "B.Cu")
		(net "GND")
	)
	(via
		(at 32.947102 -9.424924)
		(size 0.508)
		(drill 0.254)
		(layers "F.Cu" "B.Cu")
		(net "GND")
	)
	(via
		(at 342.303862 -287.28924)
		(size 0.4572)
		(drill 0.2032)
		(layers "F.Cu" "B.Cu")
		(net "GND")
	)
	(via
		(at 268.829282 -221.116652)
		(size 0.4572)
		(drill 0.2032)
		(layers "F.Cu" "B.Cu")
		(net "GND")
	)
	(via
		(at 428.279814 -195.616576)
		(size 0.4572)
		(drill 0.2032)
		(layers "F.Cu" "B.Cu")
		(net "GND")
	)
	(via
		(at 277.607014 -251.716794)
		(size 0.4572)
		(drill 0.2032)
		(layers "F.Cu" "B.Cu")
		(net "GND")
	)
	(via
		(at 214.615014 -216.866724)
		(size 0.4572)
		(drill 0.2032)
		(layers "F.Cu" "B.Cu")
		(net "GND")
	)
	(via
		(at 427.229016 -136.41451)
		(size 0.508)
		(drill 0.254)
		(layers "F.Cu" "B.Cu")
		(net "GND")
	)
	(via
		(at 340.589362 -73.85177)
		(size 0.508)
		(drill 0.254)
		(layers "F.Cu" "B.Cu")
		(net "GND")
	)
	(via
		(at 449.677282 -202.416664)
		(size 0.4572)
		(drill 0.2032)
		(layers "F.Cu" "B.Cu")
		(net "GND")
	)
	(via
		(at 346.063062 -266.128246)
		(size 0.4572)
		(drill 0.2032)
		(layers "F.Cu" "B.Cu")
		(net "GND")
	)
	(via
		(at 47.360078 -102.888034)
		(size 0.508)
		(drill 0.254)
		(layers "F.Cu" "B.Cu")
		(net "GND")
	)
	(via
		(at 342.19388 -243.108988)
		(size 0.4572)
		(drill 0.2032)
		(layers "F.Cu" "B.Cu")
		(net "GND")
	)
	(via
		(at 339.844634 -219.506038)
		(size 0.4572)
		(drill 0.2032)
		(layers "F.Cu" "B.Cu")
		(net "GND")
	)
	(via
		(at 354.74021 -360.753406)
		(size 0.508)
		(drill 0.254)
		(layers "F.Cu" "B.Cu")
		(net "GND")
	)
	(via
		(at 427.045882 -233.86669)
		(size 0.4572)
		(drill 0.2032)
		(layers "F.Cu" "B.Cu")
		(net "GND")
	)
	(via
		(at 465.326476 -387.598158)
		(size 0.508)
		(drill 0.254)
		(layers "F.Cu" "B.Cu")
		(net "GND")
	)
	(via
		(at 70.48373 -403.249892)
		(size 0.4572)
		(drill 0.254)
		(layers "F.Cu" "B.Cu")
		(net "GND")
	)
	(via
		(at 188.68136 -10.117328)
		(size 0.508)
		(drill 0.254)
		(layers "F.Cu" "B.Cu")
		(net "GND")
	)
	(via
		(at 69.127878 -407.00452)
		(size 0.4064)
		(drill 0.2032)
		(layers "F.Cu" "B.Cu")
		(net "GND")
	)
	(via
		(at 195.427346 -296.766742)
		(size 0.4572)
		(drill 0.2032)
		(layers "F.Cu" "B.Cu")
		(net "GND")
	)
	(via
		(at 368.121184 -104.266238)
		(size 0.508)
		(drill 0.254)
		(layers "F.Cu" "B.Cu")
		(net "GND")
	)
	(via
		(at 422.142412 -19.759422)
		(size 0.508)
		(drill 0.254)
		(layers "F.Cu" "B.Cu")
		(net "GND")
	)
	(via
		(at 383.075434 -237.411514)
		(size 0.4572)
		(drill 0.2032)
		(layers "F.Cu" "B.Cu")
		(net "GND")
	)
	(via
		(at 287.360614 -300.166786)
		(size 0.4572)
		(drill 0.2032)
		(layers "F.Cu" "B.Cu")
		(net "GND")
	)
	(via
		(at 73.10628 -184.902348)
		(size 0.508)
		(drill 0.254)
		(layers "F.Cu" "B.Cu")
		(net "GND")
	)
	(via
		(at 291.460682 -224.516696)
		(size 0.4572)
		(drill 0.2032)
		(layers "F.Cu" "B.Cu")
		(net "GND")
	)
	(via
		(at 411.958282 -299.316648)
		(size 0.4572)
		(drill 0.2032)
		(layers "F.Cu" "B.Cu")
		(net "GND")
	)
	(via
		(at 101.302566 -235.783882)
		(size 0.4572)
		(drill 0.2032)
		(layers "F.Cu" "B.Cu")
		(net "GND")
	)
	(via
		(at 194.193414 -241.516662)
		(size 0.4572)
		(drill 0.2032)
		(layers "F.Cu" "B.Cu")
		(net "GND")
	)
	(via
		(at 287.284668 -363.337094)
		(size 0.49022)
		(drill 0.254)
		(layers "F.Cu" "B.Cu")
		(net "GND")
	)
	(via
		(at 364.389416 -283.219906)
		(size 0.4572)
		(drill 0.2032)
		(layers "F.Cu" "B.Cu")
		(net "GND")
	)
	(via
		(at 270.063214 -272.116804)
		(size 0.4572)
		(drill 0.2032)
		(layers "F.Cu" "B.Cu")
		(net "GND")
	)
	(via
		(at 182.675276 -54.152546)
		(size 0.508)
		(drill 0.254)
		(layers "F.Cu" "B.Cu")
		(net "GND")
	)
	(via
		(at 63.942214 -226.216718)
		(size 0.4572)
		(drill 0.2032)
		(layers "F.Cu" "B.Cu")
		(net "GND")
	)
	(via
		(at 157.708346 -270.416782)
		(size 0.4572)
		(drill 0.2032)
		(layers "F.Cu" "B.Cu")
		(net "GND")
	)
	(via
		(at 112.300512 -400.019266)
		(size 0.508)
		(drill 0.254)
		(layers "F.Cu" "B.Cu")
		(net "GND")
	)
	(via
		(at 2.764536 -223.950022)
		(size 0.508)
		(drill 0.254)
		(layers "F.Cu" "B.Cu")
		(net "GND")
	)
	(via
		(at 59.842146 -244.916706)
		(size 0.4572)
		(drill 0.2032)
		(layers "F.Cu" "B.Cu")
		(net "GND")
	)
	(via
		(at 197.637146 -246.616728)
		(size 0.4572)
		(drill 0.2032)
		(layers "F.Cu" "B.Cu")
		(net "GND")
	)
	(via
		(at 261.285482 -249.166634)
		(size 0.4572)
		(drill 0.2032)
		(layers "F.Cu" "B.Cu")
		(net "GND")
	)
	(via
		(at 414.16478 -176.367948)
		(size 0.508)
		(drill 0.254)
		(layers "F.Cu" "B.Cu")
		(net "GND")
	)
	(via
		(at 375.121932 -57.263792)
		(size 0.508)
		(drill 0.254)
		(layers "F.Cu" "B.Cu")
		(net "GND")
	)
	(via
		(at 367.227358 -91.953334)
		(size 0.508)
		(drill 0.254)
		(layers "F.Cu" "B.Cu")
		(net "GND")
	)
	(via
		(at 176.6824 -95.367348)
		(size 0.508)
		(drill 0.254)
		(layers "F.Cu" "B.Cu")
		(net "GND")
	)
	(via
		(at 216.824814 -196.466714)
		(size 0.4572)
		(drill 0.2032)
		(layers "F.Cu" "B.Cu")
		(net "GND")
	)
	(via
		(at 462.555082 -245.76659)
		(size 0.4572)
		(drill 0.2032)
		(layers "F.Cu" "B.Cu")
		(net "GND")
	)
	(via
		(at 71.82993 -406.370536)
		(size 0.4572)
		(drill 0.254)
		(layers "F.Cu" "B.Cu")
		(net "GND")
	)
	(via
		(at 20.889214 -219.41663)
		(size 0.4572)
		(drill 0.2032)
		(layers "F.Cu" "B.Cu")
		(net "GND")
	)
	(via
		(at 302.448214 -246.616728)
		(size 0.4572)
		(drill 0.2032)
		(layers "F.Cu" "B.Cu")
		(net "GND")
	)
	(via
		(at 28.433014 -205.816708)
		(size 0.4572)
		(drill 0.2032)
		(layers "F.Cu" "B.Cu")
		(net "GND")
	)
	(via
		(at 401.349972 -434.899562)
		(size 0.4572)
		(drill 0.2032)
		(layers "F.Cu" "B.Cu")
		(net "GND")
	)
	(via
		(at 53.233066 -117.40769)
		(size 0.508)
		(drill 0.254)
		(layers "F.Cu" "B.Cu")
		(net "GND")
	)
	(via
		(at 153.34996 -433.747164)
		(size 0.4572)
		(drill 0.2032)
		(layers "F.Cu" "B.Cu")
		(net "GND")
	)
	(via
		(at 382.478534 -54.813708)
		(size 0.508)
		(drill 0.254)
		(layers "F.Cu" "B.Cu")
		(net "GND")
	)
	(via
		(at 419.502082 -196.466714)
		(size 0.4572)
		(drill 0.2032)
		(layers "F.Cu" "B.Cu")
		(net "GND")
	)
	(via
		(at 313.957208 -410.030168)
		(size 0.4064)
		(drill 0.2032)
		(layers "F.Cu" "B.Cu")
		(net "GND")
	)
	(via
		(at 453.30872 -394.696188)
		(size 0.6604)
		(drill 0.3302)
		(layers "F.Cu" "B.Cu")
		(net "GND")
	)
	(via
		(at 253.93269 -39.101522)
		(size 0.508)
		(drill 0.254)
		(layers "F.Cu" "B.Cu")
		(net "GND")
	)
	(via
		(at 333.7433 -66.449448)
		(size 0.508)
		(drill 0.254)
		(layers "F.Cu" "B.Cu")
		(net "GND")
	)
	(via
		(at 374.726962 -289.807142)
		(size 0.4572)
		(drill 0.2032)
		(layers "F.Cu" "B.Cu")
		(net "GND")
	)
	(via
		(at 81.564226 -333.529432)
		(size 0.508)
		(drill 0.254)
		(layers "F.Cu" "B.Cu")
		(net "GND")
	)
	(via
		(at 435.823614 -263.616694)
		(size 0.4572)
		(drill 0.2032)
		(layers "F.Cu" "B.Cu")
		(net "GND")
	)
	(via
		(at 276.373082 -308.666642)
		(size 0.4572)
		(drill 0.2032)
		(layers "F.Cu" "B.Cu")
		(net "GND")
	)
	(via
		(at 401.349972 -428.851314)
		(size 0.4572)
		(drill 0.2032)
		(layers "F.Cu" "B.Cu")
		(net "GND")
	)
	(via
		(at 277.607014 -292.516814)
		(size 0.4572)
		(drill 0.2032)
		(layers "F.Cu" "B.Cu")
		(net "GND")
	)
	(via
		(at 366.738662 -271.011396)
		(size 0.4572)
		(drill 0.2032)
		(layers "F.Cu" "B.Cu")
		(net "GND")
	)
	(via
		(at 81.01965 -409.396184)
		(size 0.4572)
		(drill 0.254)
		(layers "F.Cu" "B.Cu")
		(net "GND")
	)
	(via
		(at 302.235108 -163.089844)
		(size 0.508)
		(drill 0.254)
		(layers "F.Cu" "B.Cu")
		(net "GND")
	)
	(via
		(at 186.649614 -297.616626)
		(size 0.4572)
		(drill 0.2032)
		(layers "F.Cu" "B.Cu")
		(net "GND")
	)
	(via
		(at 62.051946 -300.166786)
		(size 0.4572)
		(drill 0.2032)
		(layers "F.Cu" "B.Cu")
		(net "GND")
	)
	(via
		(at 264.729214 -236.416596)
		(size 0.4572)
		(drill 0.2032)
		(layers "F.Cu" "B.Cu")
		(net "GND")
	)
	(via
		(at 336.08518 -335.976214)
		(size 0.49022)
		(drill 0.254)
		(layers "F.Cu" "B.Cu")
		(net "GND")
	)
	(via
		(at 52.082446 -234.716574)
		(size 0.4572)
		(drill 0.2032)
		(layers "F.Cu" "B.Cu")
		(net "GND")
	)
	(via
		(at 439.923682 -271.266666)
		(size 0.4572)
		(drill 0.2032)
		(layers "F.Cu" "B.Cu")
		(net "GND")
	)
	(via
		(at 277.607014 -311.216802)
		(size 0.4572)
		(drill 0.2032)
		(layers "F.Cu" "B.Cu")
		(net "GND")
	)
	(via
		(at 188.63437 -426.303948)
		(size 0.508)
		(drill 0.254)
		(layers "F.Cu" "B.Cu")
		(net "GND")
	)
	(via
		(at 338.396072 -42.341546)
		(size 0.4572)
		(drill 0.2032)
		(layers "F.Cu" "B.Cu")
		(net "GND")
	)
	(via
		(at 125.00737 -330.42352)
		(size 0.508)
		(drill 0.254)
		(layers "F.Cu" "B.Cu")
		(net "GND")
	)
	(via
		(at 43.520614 -247.466612)
		(size 0.4572)
		(drill 0.2032)
		(layers "F.Cu" "B.Cu")
		(net "GND")
	)
	(via
		(at 300.54042 -187.731908)
		(size 0.508)
		(drill 0.254)
		(layers "F.Cu" "B.Cu")
		(net "GND")
	)
	(via
		(at 323.229478 -69.198744)
		(size 0.508)
		(drill 0.254)
		(layers "F.Cu" "B.Cu")
		(net "GND")
	)
	(via
		(at 93.34246 -338.472272)
		(size 0.508)
		(drill 0.254)
		(layers "F.Cu" "B.Cu")
		(net "GND")
	)
	(via
		(at 131.015994 -280.778204)
		(size 0.4572)
		(drill 0.2032)
		(layers "F.Cu" "B.Cu")
		(net "GND")
	)
	(via
		(at 351.231962 -273.453098)
		(size 0.4572)
		(drill 0.2032)
		(layers "F.Cu" "B.Cu")
		(net "GND")
	)
	(via
		(at 464.764882 -305.266598)
		(size 0.4572)
		(drill 0.2032)
		(layers "F.Cu" "B.Cu")
		(net "GND")
	)
	(via
		(at 178.23942 -365.21517)
		(size 0.508)
		(drill 0.254)
		(layers "F.Cu" "B.Cu")
		(net "GND")
	)
	(via
		(at 408.061414 -236.397038)
		(size 0.4572)
		(drill 0.2032)
		(layers "F.Cu" "B.Cu")
		(net "GND")
	)
	(via
		(at 120.568212 -231.714548)
		(size 0.4572)
		(drill 0.2032)
		(layers "F.Cu" "B.Cu")
		(net "GND")
	)
	(via
		(at 28.433014 -224.516696)
		(size 0.4572)
		(drill 0.2032)
		(layers "F.Cu" "B.Cu")
		(net "GND")
	)
	(via
		(at 325.15429 -341.681308)
		(size 0.508)
		(drill 0.254)
		(layers "F.Cu" "B.Cu")
		(net "GND")
	)
	(via
		(at 167.461946 -201.56678)
		(size 0.4572)
		(drill 0.2032)
		(layers "F.Cu" "B.Cu")
		(net "GND")
	)
	(via
		(at 22.123146 -248.31675)
		(size 0.4572)
		(drill 0.2032)
		(layers "F.Cu" "B.Cu")
		(net "GND")
	)
	(via
		(at 259.075682 -275.516594)
		(size 0.4572)
		(drill 0.2032)
		(layers "F.Cu" "B.Cu")
		(net "GND")
	)
	(via
		(at 164.018214 -314.616592)
		(size 0.4572)
		(drill 0.2032)
		(layers "F.Cu" "B.Cu")
		(net "GND")
	)
	(via
		(at 51.064414 -310.366664)
		(size 0.4572)
		(drill 0.2032)
		(layers "F.Cu" "B.Cu")
		(net "GND")
	)
	(via
		(at 110.340394 -277.522432)
		(size 0.4572)
		(drill 0.2032)
		(layers "F.Cu" "B.Cu")
		(net "GND")
	)
	(via
		(at 270.063214 -197.316598)
		(size 0.4572)
		(drill 0.2032)
		(layers "F.Cu" "B.Cu")
		(net "GND")
	)
	(via
		(at 139.878054 -247.042432)
		(size 0.4572)
		(drill 0.2032)
		(layers "F.Cu" "B.Cu")
		(net "GND")
	)
	(via
		(at 358.280462 -274.266914)
		(size 0.4572)
		(drill 0.2032)
		(layers "F.Cu" "B.Cu")
		(net "GND")
	)
	(via
		(at 272.273014 -307.816758)
		(size 0.4572)
		(drill 0.2032)
		(layers "F.Cu" "B.Cu")
		(net "GND")
	)
	(via
		(at 30.915864 -4.962652)
		(size 0.508)
		(drill 0.254)
		(layers "F.Cu" "B.Cu")
		(net "GND")
	)
	(via
		(at 259.075682 -267.866622)
		(size 0.4572)
		(drill 0.2032)
		(layers "F.Cu" "B.Cu")
		(net "GND")
	)
	(via
		(at 333.26578 -222.761556)
		(size 0.4572)
		(drill 0.2032)
		(layers "F.Cu" "B.Cu")
		(net "GND")
	)
	(via
		(at 180.339746 -242.3668)
		(size 0.4572)
		(drill 0.2032)
		(layers "F.Cu" "B.Cu")
		(net "GND")
	)
	(via
		(at 39.420546 -287.416748)
		(size 0.4572)
		(drill 0.2032)
		(layers "F.Cu" "B.Cu")
		(net "GND")
	)
	(via
		(at 157.708346 -317.166752)
		(size 0.4572)
		(drill 0.2032)
		(layers "F.Cu" "B.Cu")
		(net "GND")
	)
	(via
		(at 100.208334 -331.71892)
		(size 0.508)
		(drill 0.254)
		(layers "F.Cu" "B.Cu")
		(net "GND")
	)
	(via
		(at 353.111816 -281.59202)
		(size 0.4572)
		(drill 0.2032)
		(layers "F.Cu" "B.Cu")
		(net "GND")
	)
	(via
		(at 276.373082 -280.61666)
		(size 0.4572)
		(drill 0.2032)
		(layers "F.Cu" "B.Cu")
		(net "GND")
	)
	(via
		(at 91.652598 -410.030168)
		(size 0.4064)
		(drill 0.2032)
		(layers "F.Cu" "B.Cu")
		(net "GND")
	)
	(via
		(at 270.063214 -236.416596)
		(size 0.4572)
		(drill 0.2032)
		(layers "F.Cu" "B.Cu")
		(net "GND")
	)
	(via
		(at 385.424934 -246.364506)
		(size 0.4572)
		(drill 0.2032)
		(layers "F.Cu" "B.Cu")
		(net "GND")
	)
	(via
		(at 11.135614 -226.216718)
		(size 0.4572)
		(drill 0.2032)
		(layers "F.Cu" "B.Cu")
		(net "GND")
	)
	(via
		(at 142.746222 -407.638504)
		(size 0.4572)
		(drill 0.254)
		(layers "F.Cu" "B.Cu")
		(net "GND")
	)
	(via
		(at 327.250044 -426.69968)
		(size 0.4572)
		(drill 0.2032)
		(layers "F.Cu" "B.Cu")
		(net "GND")
	)
	(via
		(at 90.964512 -235.783882)
		(size 0.4572)
		(drill 0.2032)
		(layers "F.Cu" "B.Cu")
		(net "GND")
	)
	(via
		(at 113.519966 -226.017328)
		(size 0.4572)
		(drill 0.2032)
		(layers "F.Cu" "B.Cu")
		(net "GND")
	)
	(via
		(at 56.398414 -200.716642)
		(size 0.4572)
		(drill 0.2032)
		(layers "F.Cu" "B.Cu")
		(net "GND")
	)
	(via
		(at 167.164766 -400.224244)
		(size 0.4572)
		(drill 0.254)
		(layers "F.Cu" "B.Cu")
		(net "GND")
	)
	(via
		(at 182.675276 -48.22571)
		(size 0.508)
		(drill 0.254)
		(layers "F.Cu" "B.Cu")
		(net "GND")
	)
	(via
		(at 339.014562 -262.058658)
		(size 0.4572)
		(drill 0.2032)
		(layers "F.Cu" "B.Cu")
		(net "GND")
	)
	(via
		(at 401.349972 -437.34736)
		(size 0.4572)
		(drill 0.2032)
		(layers "F.Cu" "B.Cu")
		(net "GND")
	)
	(via
		(at 113.523776 -339.325712)
		(size 0.508)
		(drill 0.254)
		(layers "F.Cu" "B.Cu")
		(net "GND")
	)
	(via
		(at 455.011282 -289.966654)
		(size 0.4572)
		(drill 0.2032)
		(layers "F.Cu" "B.Cu")
		(net "GND")
	)
	(via
		(at 330.89342 -407.638504)
		(size 0.4572)
		(drill 0.254)
		(layers "F.Cu" "B.Cu")
		(net "GND")
	)
	(via
		(at 127.342646 -401.492212)
		(size 0.4572)
		(drill 0.254)
		(layers "F.Cu" "B.Cu")
		(net "GND")
	)
	(via
		(at 424.836082 -261.066788)
		(size 0.4572)
		(drill 0.2032)
		(layers "F.Cu" "B.Cu")
		(net "GND")
	)
	(via
		(at 7.035546 -214.316564)
		(size 0.4572)
		(drill 0.2032)
		(layers "F.Cu" "B.Cu")
		(net "GND")
	)
	(via
		(at 340.305136 -333.173324)
		(size 0.508)
		(drill 0.254)
		(layers "F.Cu" "B.Cu")
		(net "GND")
	)
	(via
		(at 448.916552 -323.429376)
		(size 0.4572)
		(drill 0.2032)
		(layers "F.Cu" "B.Cu")
		(net "GND")
	)
	(via
		(at 299.004482 -284.866588)
		(size 0.4572)
		(drill 0.2032)
		(layers "F.Cu" "B.Cu")
		(net "GND")
	)
	(via
		(at 133.469126 -403.249892)
		(size 0.4572)
		(drill 0.254)
		(layers "F.Cu" "B.Cu")
		(net "GND")
	)
	(via
		(at 20.889214 -289.966654)
		(size 0.4572)
		(drill 0.2032)
		(layers "F.Cu" "B.Cu")
		(net "GND")
	)
	(via
		(at 443.367414 -270.416782)
		(size 0.4572)
		(drill 0.2032)
		(layers "F.Cu" "B.Cu")
		(net "GND")
	)
	(via
		(at 328.625708 -51.269646)
		(size 0.4572)
		(drill 0.2032)
		(layers "F.Cu" "B.Cu")
		(net "GND")
	)
	(via
		(at 274.163282 -205.816708)
		(size 0.4572)
		(drill 0.2032)
		(layers "F.Cu" "B.Cu")
		(net "GND")
	)
	(via
		(at 462.120996 -104.249728)
		(size 0.508)
		(drill 0.254)
		(layers "F.Cu" "B.Cu")
		(net "GND")
	)
	(via
		(at 82.250026 -438.499758)
		(size 0.4572)
		(drill 0.2032)
		(layers "F.Cu" "B.Cu")
		(net "GND")
	)
	(via
		(at 300.238414 -304.416714)
		(size 0.4572)
		(drill 0.2032)
		(layers "F.Cu" "B.Cu")
		(net "GND")
	)
	(via
		(at 446.9638 -14.646148)
		(size 0.508)
		(drill 0.254)
		(layers "F.Cu" "B.Cu")
		(net "GND")
	)
	(via
		(at 445.639952 -319.345056)
		(size 0.4572)
		(drill 0.2032)
		(layers "F.Cu" "B.Cu")
		(net "GND")
	)
	(via
		(at 343.243662 -267.755878)
		(size 0.4572)
		(drill 0.2032)
		(layers "F.Cu" "B.Cu")
		(net "GND")
	)
	(via
		(at 254.975614 -301.866808)
		(size 0.4572)
		(drill 0.2032)
		(layers "F.Cu" "B.Cu")
		(net "GND")
	)
	(via
		(at 409.551632 -219.41663)
		(size 0.4572)
		(drill 0.2032)
		(layers "F.Cu" "B.Cu")
		(net "GND")
	)
	(via
		(at 458.455014 -223.666558)
		(size 0.4572)
		(drill 0.2032)
		(layers "F.Cu" "B.Cu")
		(net "GND")
	)
	(via
		(at 349.352362 -263.686544)
		(size 0.4572)
		(drill 0.2032)
		(layers "F.Cu" "B.Cu")
		(net "GND")
	)
	(via
		(at 299.004482 -266.1666)
		(size 0.4572)
		(drill 0.2032)
		(layers "F.Cu" "B.Cu")
		(net "GND")
	)
	(via
		(at 44.754546 -195.616576)
		(size 0.4572)
		(drill 0.2032)
		(layers "F.Cu" "B.Cu")
		(net "GND")
	)
	(via
		(at 462.555082 -216.866724)
		(size 0.4572)
		(drill 0.2032)
		(layers "F.Cu" "B.Cu")
		(net "GND")
	)
	(via
		(at 389.50773 -410.030168)
		(size 0.4064)
		(drill 0.2032)
		(layers "F.Cu" "B.Cu")
		(net "GND")
	)
	(via
		(at 36.40836 -51.973988)
		(size 0.508)
		(drill 0.254)
		(layers "F.Cu" "B.Cu")
		(net "GND")
	)
	(via
		(at 297.122088 -360.83621)
		(size 0.49022)
		(drill 0.254)
		(layers "F.Cu" "B.Cu")
		(net "GND")
	)
	(via
		(at 407.858214 -231.316784)
		(size 0.4572)
		(drill 0.2032)
		(layers "F.Cu" "B.Cu")
		(net "GND")
	)
	(via
		(at 41.310814 -226.216718)
		(size 0.4572)
		(drill 0.2032)
		(layers "F.Cu" "B.Cu")
		(net "GND")
	)
	(via
		(at 175.005746 -267.016738)
		(size 0.4572)
		(drill 0.2032)
		(layers "F.Cu" "B.Cu")
		(net "GND")
	)
	(via
		(at 212.724746 -313.766708)
		(size 0.4572)
		(drill 0.2032)
		(layers "F.Cu" "B.Cu")
		(net "GND")
	)
	(via
		(at 136.545066 -218.692222)
		(size 0.4572)
		(drill 0.2032)
		(layers "F.Cu" "B.Cu")
		(net "GND")
	)
	(via
		(at 194.527932 -22.18436)
		(size 0.508)
		(drill 0.254)
		(layers "F.Cu" "B.Cu")
		(net "GND")
	)
	(via
		(at 190.093346 -216.016586)
		(size 0.4572)
		(drill 0.2032)
		(layers "F.Cu" "B.Cu")
		(net "GND")
	)
	(via
		(at 332.250034 -429.147224)
		(size 0.4572)
		(drill 0.2032)
		(layers "F.Cu" "B.Cu")
		(net "GND")
	)
	(via
		(at 192.415668 -360.853736)
		(size 0.508)
		(drill 0.254)
		(layers "F.Cu" "B.Cu")
		(net "GND")
	)
	(via
		(at 297.57116 -78.969108)
		(size 0.508)
		(drill 0.254)
		(layers "F.Cu" "B.Cu")
		(net "GND")
	)
	(via
		(at 131.846066 -230.086662)
		(size 0.4572)
		(drill 0.2032)
		(layers "F.Cu" "B.Cu")
		(net "GND")
	)
	(via
		(at 344.07348 -239.853216)
		(size 0.4572)
		(drill 0.2032)
		(layers "F.Cu" "B.Cu")
		(net "GND")
	)
	(via
		(at 330.706222 -35.677348)
		(size 0.508)
		(drill 0.254)
		(layers "F.Cu" "B.Cu")
		(net "GND")
	)
	(via
		(at 415.402014 -267.016738)
		(size 0.4572)
		(drill 0.2032)
		(layers "F.Cu" "B.Cu")
		(net "GND")
	)
	(via
		(at 140.349986 -439.651394)
		(size 0.4572)
		(drill 0.2032)
		(layers "F.Cu" "B.Cu")
		(net "GND")
	)
	(via
		(at 16.789146 -216.016586)
		(size 0.4572)
		(drill 0.2032)
		(layers "F.Cu" "B.Cu")
		(net "GND")
	)
	(via
		(at 161.125662 -406.370536)
		(size 0.4572)
		(drill 0.254)
		(layers "F.Cu" "B.Cu")
		(net "GND")
	)
	(via
		(at 292.694614 -242.3668)
		(size 0.4572)
		(drill 0.2032)
		(layers "F.Cu" "B.Cu")
		(net "GND")
	)
	(via
		(at 216.824814 -228.766624)
		(size 0.4572)
		(drill 0.2032)
		(layers "F.Cu" "B.Cu")
		(net "GND")
	)
	(via
		(at 169.352214 -250.866656)
		(size 0.4572)
		(drill 0.2032)
		(layers "F.Cu" "B.Cu")
		(net "GND")
	)
	(via
		(at 374.726962 -255.547622)
		(size 0.4572)
		(drill 0.2032)
		(layers "F.Cu" "B.Cu")
		(net "GND")
	)
	(via
		(at 450.053964 -441.225432)
		(size 0.508)
		(drill 0.254)
		(layers "F.Cu" "B.Cu")
		(net "GND")
	)
	(via
		(at 171.562014 -200.716642)
		(size 0.4572)
		(drill 0.2032)
		(layers "F.Cu" "B.Cu")
		(net "GND")
	)
	(via
		(at 304.767488 -410.030168)
		(size 0.4064)
		(drill 0.2032)
		(layers "F.Cu" "B.Cu")
		(net "GND")
	)
	(via
		(at 43.520614 -228.766624)
		(size 0.4572)
		(drill 0.2032)
		(layers "F.Cu" "B.Cu")
		(net "GND")
	)
	(via
		(at 314.092082 -286.56661)
		(size 0.4572)
		(drill 0.2032)
		(layers "F.Cu" "B.Cu")
		(net "GND")
	)
	(via
		(at 32.30753 -428.843948)
		(size 0.508)
		(drill 0.254)
		(layers "F.Cu" "B.Cu")
		(net "GND")
	)
	(via
		(at 261.163308 -67.904868)
		(size 0.508)
		(drill 0.254)
		(layers "F.Cu" "B.Cu")
		(net "GND")
	)
	(via
		(at 460.837788 -12.544552)
		(size 0.508)
		(drill 0.254)
		(layers "F.Cu" "B.Cu")
		(net "GND")
	)
	(via
		(at 337.49488 -241.481102)
		(size 0.4572)
		(drill 0.2032)
		(layers "F.Cu" "B.Cu")
		(net "GND")
	)
	(via
		(at 377.43638 -234.15625)
		(size 0.4572)
		(drill 0.2032)
		(layers "F.Cu" "B.Cu")
		(net "GND")
	)
	(via
		(at 259.075682 -266.1666)
		(size 0.4572)
		(drill 0.2032)
		(layers "F.Cu" "B.Cu")
		(net "GND")
	)
	(via
		(at 371.437662 -262.872474)
		(size 0.4572)
		(drill 0.2032)
		(layers "F.Cu" "B.Cu")
		(net "GND")
	)
	(via
		(at 295.91 -48.504348)
		(size 0.508)
		(drill 0.254)
		(layers "F.Cu" "B.Cu")
		(net "GND")
	)
	(via
		(at 321.8561 -77.723492)
		(size 0.508)
		(drill 0.254)
		(layers "F.Cu" "B.Cu")
		(net "GND")
	)
	(via
		(at 296.97299 -364.759494)
		(size 0.49022)
		(drill 0.254)
		(layers "F.Cu" "B.Cu")
		(net "GND")
	)
	(via
		(at 132.785866 -238.225584)
		(size 0.4572)
		(drill 0.2032)
		(layers "F.Cu" "B.Cu")
		(net "GND")
	)
	(via
		(at 135.135112 -224.389442)
		(size 0.4572)
		(drill 0.2032)
		(layers "F.Cu" "B.Cu")
		(net "GND")
	)
	(via
		(at 7.035546 -289.11677)
		(size 0.4572)
		(drill 0.2032)
		(layers "F.Cu" "B.Cu")
		(net "GND")
	)
	(via
		(at 453.121014 -287.416748)
		(size 0.4572)
		(drill 0.2032)
		(layers "F.Cu" "B.Cu")
		(net "GND")
	)
	(via
		(at 432.974496 -110.1471)
		(size 0.508)
		(drill 0.254)
		(layers "F.Cu" "B.Cu")
		(net "GND")
	)
	(via
		(at 101.412294 -273.453098)
		(size 0.4572)
		(drill 0.2032)
		(layers "F.Cu" "B.Cu")
		(net "GND")
	)
	(via
		(at 66.367914 -272.966688)
		(size 0.4572)
		(drill 0.2032)
		(layers "F.Cu" "B.Cu")
		(net "GND")
	)
	(via
		(at 7.035546 -195.616576)
		(size 0.4572)
		(drill 0.2032)
		(layers "F.Cu" "B.Cu")
		(net "GND")
	)
	(via
		(at 377.43638 -243.922804)
		(size 0.4572)
		(drill 0.2032)
		(layers "F.Cu" "B.Cu")
		(net "GND")
	)
	(via
		(at 289.250882 -280.61666)
		(size 0.4572)
		(drill 0.2032)
		(layers "F.Cu" "B.Cu")
		(net "GND")
	)
	(via
		(at 386.350002 -427.851316)
		(size 0.4572)
		(drill 0.2032)
		(layers "F.Cu" "B.Cu")
		(net "GND")
	)
	(via
		(at 201.737214 -284.866588)
		(size 0.4572)
		(drill 0.2032)
		(layers "F.Cu" "B.Cu")
		(net "GND")
	)
	(via
		(at 197.637146 -210.916774)
		(size 0.4572)
		(drill 0.2032)
		(layers "F.Cu" "B.Cu")
		(net "GND")
	)
	(via
		(at 337.716368 -73.89368)
		(size 0.508)
		(drill 0.254)
		(layers "F.Cu" "B.Cu")
		(net "GND")
	)
	(via
		(at 461.819752 -323.353176)
		(size 0.4572)
		(drill 0.2032)
		(layers "F.Cu" "B.Cu")
		(net "GND")
	)
	(via
		(at 29.346906 -7.215124)
		(size 0.508)
		(drill 0.254)
		(layers "F.Cu" "B.Cu")
		(net "GND")
	)
	(via
		(at 449.677282 -224.516696)
		(size 0.4572)
		(drill 0.2032)
		(layers "F.Cu" "B.Cu")
		(net "GND")
	)
	(via
		(at 99.422966 -226.017328)
		(size 0.4572)
		(drill 0.2032)
		(layers "F.Cu" "B.Cu")
		(net "GND")
	)
	(via
		(at 426.25137 -5.585714)
		(size 0.508)
		(drill 0.254)
		(layers "F.Cu" "B.Cu")
		(net "GND")
	)
	(via
		(at 217.095324 -58.389012)
		(size 0.508)
		(drill 0.254)
		(layers "F.Cu" "B.Cu")
		(net "GND")
	)
	(via
		(at 101.412548 -271.825212)
		(size 0.4572)
		(drill 0.2032)
		(layers "F.Cu" "B.Cu")
		(net "GND")
	)
	(via
		(at 16.994124 -405.974296)
		(size 0.508)
		(drill 0.254)
		(layers "F.Cu" "B.Cu")
		(net "GND")
	)
	(via
		(at 126.786894 -281.59202)
		(size 0.4572)
		(drill 0.2032)
		(layers "F.Cu" "B.Cu")
		(net "GND")
	)
	(via
		(at 283.916882 -226.216718)
		(size 0.4572)
		(drill 0.2032)
		(layers "F.Cu" "B.Cu")
		(net "GND")
	)
	(via
		(at 99.532948 -253.919736)
		(size 0.4572)
		(drill 0.2032)
		(layers "F.Cu" "B.Cu")
		(net "GND")
	)
	(via
		(at 43.520614 -230.466646)
		(size 0.4572)
		(drill 0.2032)
		(layers "F.Cu" "B.Cu")
		(net "GND")
	)
	(via
		(at 424.974766 -362.649262)
		(size 0.49022)
		(drill 0.254)
		(layers "F.Cu" "B.Cu")
		(net "GND")
	)
	(via
		(at 45.064934 -351.535238)
		(size 0.508)
		(drill 0.254)
		(layers "F.Cu" "B.Cu")
		(net "GND")
	)
	(via
		(at 300.238414 -267.016738)
		(size 0.4572)
		(drill 0.2032)
		(layers "F.Cu" "B.Cu")
		(net "GND")
	)
	(via
		(at 133.346952 -12.495276)
		(size 0.508)
		(drill 0.254)
		(layers "F.Cu" "B.Cu")
		(net "GND")
	)
	(via
		(at 309.992014 -229.616762)
		(size 0.4572)
		(drill 0.2032)
		(layers "F.Cu" "B.Cu")
		(net "GND")
	)
	(via
		(at 314.307982 -210.066636)
		(size 0.4572)
		(drill 0.2032)
		(layers "F.Cu" "B.Cu")
		(net "GND")
	)
	(via
		(at 47.634906 -18.502376)
		(size 0.508)
		(drill 0.254)
		(layers "F.Cu" "B.Cu")
		(net "GND")
	)
	(via
		(at 450.911214 -283.166566)
		(size 0.4572)
		(drill 0.2032)
		(layers "F.Cu" "B.Cu")
		(net "GND")
	)
	(via
		(at 387.598158 -74.534776)
		(size 0.6604)
		(drill 0.3302)
		(layers "F.Cu" "B.Cu")
		(net "GND")
	)
	(via
		(at 378.956062 -271.011396)
		(size 0.4572)
		(drill 0.2032)
		(layers "F.Cu" "B.Cu")
		(net "GND")
	)
	(via
		(at 272.273014 -223.666558)
		(size 0.4572)
		(drill 0.2032)
		(layers "F.Cu" "B.Cu")
		(net "GND")
	)
	(via
		(at 122.558048 -256.361438)
		(size 0.4572)
		(drill 0.2032)
		(layers "F.Cu" "B.Cu")
		(net "GND")
	)
	(via
		(at 342.19388 -228.45903)
		(size 0.4572)
		(drill 0.2032)
		(layers "F.Cu" "B.Cu")
		(net "GND")
	)
	(via
		(at 375.557034 -242.294918)
		(size 0.4572)
		(drill 0.2032)
		(layers "F.Cu" "B.Cu")
		(net "GND")
	)
	(via
		(at 443.367414 -220.266768)
		(size 0.4572)
		(drill 0.2032)
		(layers "F.Cu" "B.Cu")
		(net "GND")
	)
	(via
		(at 115.979194 -275.8948)
		(size 0.4572)
		(drill 0.2032)
		(layers "F.Cu" "B.Cu")
		(net "GND")
	)
	(via
		(at 51.743864 -4.328668)
		(size 0.508)
		(drill 0.254)
		(layers "F.Cu" "B.Cu")
		(net "GND")
	)
	(via
		(at 143.34998 -433.899564)
		(size 0.4572)
		(drill 0.2032)
		(layers "F.Cu" "B.Cu")
		(net "GND")
	)
	(via
		(at 341.724234 -242.294918)
		(size 0.4572)
		(drill 0.2032)
		(layers "F.Cu" "B.Cu")
		(net "GND")
	)
	(via
		(at 458.455014 -242.3668)
		(size 0.4572)
		(drill 0.2032)
		(layers "F.Cu" "B.Cu")
		(net "GND")
	)
	(via
		(at 171.355512 -105.375456)
		(size 0.4572)
		(drill 0.254)
		(layers "F.Cu" "B.Cu")
		(net "GND")
	)
	(via
		(at 59.842146 -236.416596)
		(size 0.4572)
		(drill 0.2032)
		(layers "F.Cu" "B.Cu")
		(net "GND")
	)
	(via
		(at 59.842146 -229.616762)
		(size 0.4572)
		(drill 0.2032)
		(layers "F.Cu" "B.Cu")
		(net "GND")
	)
	(via
		(at 405.648414 -261.916672)
		(size 0.4572)
		(drill 0.2032)
		(layers "F.Cu" "B.Cu")
		(net "GND")
	)
	(via
		(at 47.150782 -350.323658)
		(size 0.508)
		(drill 0.254)
		(layers "F.Cu" "B.Cu")
		(net "GND")
	)
	(via
		(at 197.637146 -206.666592)
		(size 0.4572)
		(drill 0.2032)
		(layers "F.Cu" "B.Cu")
		(net "GND")
	)
	(via
		(at 63.250064 -436.347362)
		(size 0.4572)
		(drill 0.2032)
		(layers "F.Cu" "B.Cu")
		(net "GND")
	)
	(via
		(at 129.496566 -226.017328)
		(size 0.4572)
		(drill 0.2032)
		(layers "F.Cu" "B.Cu")
		(net "GND")
	)
	(via
		(at 384.197098 -338.63407)
		(size 0.6604)
		(drill 0.3302)
		(layers "F.Cu" "B.Cu")
		(net "GND")
	)
	(via
		(at 323.146928 -410.030168)
		(size 0.4064)
		(drill 0.2032)
		(layers "F.Cu" "B.Cu")
		(net "GND")
	)
	(via
		(at 325.5264 -35.042348)
		(size 0.49022)
		(drill 0.254)
		(layers "F.Cu" "B.Cu")
		(net "GND")
	)
	(via
		(at 208.71688 -131.846828)
		(size 0.508)
		(drill 0.254)
		(layers "F.Cu" "B.Cu")
		(net "GND")
	)
	(via
		(at 179.105814 -235.566712)
		(size 0.4572)
		(drill 0.2032)
		(layers "F.Cu" "B.Cu")
		(net "GND")
	)
	(via
		(at 254.975614 -273.816572)
		(size 0.4572)
		(drill 0.2032)
		(layers "F.Cu" "B.Cu")
		(net "GND")
	)
	(via
		(at 368.916204 -253.19355)
		(size 0.4572)
		(drill 0.2032)
		(layers "F.Cu" "B.Cu")
		(net "GND")
	)
	(via
		(at 180.339746 -201.56678)
		(size 0.4572)
		(drill 0.2032)
		(layers "F.Cu" "B.Cu")
		(net "GND")
	)
	(via
		(at 304.338482 -266.1666)
		(size 0.4572)
		(drill 0.2032)
		(layers "F.Cu" "B.Cu")
		(net "GND")
	)
	(via
		(at 134.775194 -257.98907)
		(size 0.4572)
		(drill 0.2032)
		(layers "F.Cu" "B.Cu")
		(net "GND")
	)
	(via
		(at 335.725262 -287.28924)
		(size 0.4572)
		(drill 0.2032)
		(layers "F.Cu" "B.Cu")
		(net "GND")
	)
	(via
		(at 66.161666 -404.51786)
		(size 0.4572)
		(drill 0.254)
		(layers "F.Cu" "B.Cu")
		(net "GND")
	)
	(via
		(at 95.193866 -223.575626)
		(size 0.4572)
		(drill 0.2032)
		(layers "F.Cu" "B.Cu")
		(net "GND")
	)
	(via
		(at 283.916882 -224.516696)
		(size 0.4572)
		(drill 0.2032)
		(layers "F.Cu" "B.Cu")
		(net "GND")
	)
	(via
		(at 195.427346 -220.266768)
		(size 0.4572)
		(drill 0.2032)
		(layers "F.Cu" "B.Cu")
		(net "GND")
	)
	(via
		(at 33.767014 -228.766624)
		(size 0.4572)
		(drill 0.2032)
		(layers "F.Cu" "B.Cu")
		(net "GND")
	)
	(via
		(at 453.121014 -311.216802)
		(size 0.4572)
		(drill 0.2032)
		(layers "F.Cu" "B.Cu")
		(net "GND")
	)
	(via
		(at 428.279814 -263.616694)
		(size 0.4572)
		(drill 0.2032)
		(layers "F.Cu" "B.Cu")
		(net "GND")
	)
	(via
		(at 453.121014 -231.316784)
		(size 0.4572)
		(drill 0.2032)
		(layers "F.Cu" "B.Cu")
		(net "GND")
	)
	(via
		(at 258.572 -68.544948)
		(size 0.508)
		(drill 0.254)
		(layers "F.Cu" "B.Cu")
		(net "GND")
	)
	(via
		(at 180.339746 -263.616694)
		(size 0.4572)
		(drill 0.2032)
		(layers "F.Cu" "B.Cu")
		(net "GND")
	)
	(via
		(at 361.22483 -400.141948)
		(size 0.508)
		(drill 0.254)
		(layers "F.Cu" "B.Cu")
		(net "GND")
	)
	(via
		(at 87.785194 -259.616956)
		(size 0.4572)
		(drill 0.2032)
		(layers "F.Cu" "B.Cu")
		(net "GND")
	)
	(via
		(at 418.641276 -4.317746)
		(size 0.508)
		(drill 0.254)
		(layers "F.Cu" "B.Cu")
		(net "GND")
	)
	(via
		(at 369.138962 -338.86013)
		(size 0.508)
		(drill 0.254)
		(layers "F.Cu" "B.Cu")
		(net "GND")
	)
	(via
		(at 186.649614 -205.816708)
		(size 0.4572)
		(drill 0.2032)
		(layers "F.Cu" "B.Cu")
		(net "GND")
	)
	(via
		(at 25.39492 -430.797208)
		(size 0.508)
		(drill 0.254)
		(layers "F.Cu" "B.Cu")
		(net "GND")
	)
	(via
		(at 443.367414 -231.316784)
		(size 0.4572)
		(drill 0.2032)
		(layers "F.Cu" "B.Cu")
		(net "GND")
	)
	(via
		(at 29.666946 -313.766708)
		(size 0.4572)
		(drill 0.2032)
		(layers "F.Cu" "B.Cu")
		(net "GND")
	)
	(via
		(at 362.700316 -331.776832)
		(size 0.49022)
		(drill 0.254)
		(layers "F.Cu" "B.Cu")
		(net "GND")
	)
	(via
		(at 151.349964 -432.747166)
		(size 0.4572)
		(drill 0.2032)
		(layers "F.Cu" "B.Cu")
		(net "GND")
	)
	(via
		(at 187.883546 -229.616762)
		(size 0.4572)
		(drill 0.2032)
		(layers "F.Cu" "B.Cu")
		(net "GND")
	)
	(via
		(at 417.08451 -238.116618)
		(size 0.4572)
		(drill 0.2032)
		(layers "F.Cu" "B.Cu")
		(net "GND")
	)
	(via
		(at 410.589222 -409.396184)
		(size 0.4572)
		(drill 0.254)
		(layers "F.Cu" "B.Cu")
		(net "GND")
	)
	(via
		(at 427.045882 -219.41663)
		(size 0.4572)
		(drill 0.2032)
		(layers "F.Cu" "B.Cu")
		(net "GND")
	)
	(via
		(at 146.992594 -58.447686)
		(size 0.508)
		(drill 0.254)
		(layers "F.Cu" "B.Cu")
		(net "GND")
	)
	(via
		(at 79.80045 -344.90533)
		(size 0.49022)
		(drill 0.254)
		(layers "F.Cu" "B.Cu")
		(net "GND")
	)
	(via
		(at 113.5634 -412.130748)
		(size 0.508)
		(drill 0.254)
		(layers "F.Cu" "B.Cu")
		(net "GND")
	)
	(via
		(at 420.736014 -203.266802)
		(size 0.4572)
		(drill 0.2032)
		(layers "F.Cu" "B.Cu")
		(net "GND")
	)
	(via
		(at 340.784434 -216.25052)
		(size 0.4572)
		(drill 0.2032)
		(layers "F.Cu" "B.Cu")
		(net "GND")
	)
	(via
		(at 89.554812 -226.831144)
		(size 0.4572)
		(drill 0.2032)
		(layers "F.Cu" "B.Cu")
		(net "GND")
	)
	(via
		(at 205.45044 -153.365708)
		(size 0.508)
		(drill 0.254)
		(layers "F.Cu" "B.Cu")
		(net "GND")
	)
	(via
		(at 124.537978 -361.060746)
		(size 0.508)
		(drill 0.254)
		(layers "F.Cu" "B.Cu")
		(net "GND")
	)
	(via
		(at 97.97542 -117.074188)
		(size 0.508)
		(drill 0.254)
		(layers "F.Cu" "B.Cu")
		(net "GND")
	)
	(via
		(at 412.03245 -407.00452)
		(size 0.4064)
		(drill 0.2032)
		(layers "F.Cu" "B.Cu")
		(net "GND")
	)
	(via
		(at 384.350006 -426.54728)
		(size 0.4572)
		(drill 0.2032)
		(layers "F.Cu" "B.Cu")
		(net "GND")
	)
	(via
		(at 99.532948 -262.058658)
		(size 0.4572)
		(drill 0.2032)
		(layers "F.Cu" "B.Cu")
		(net "GND")
	)
	(via
		(at 51.064414 -301.01667)
		(size 0.4572)
		(drill 0.2032)
		(layers "F.Cu" "B.Cu")
		(net "GND")
	)
	(via
		(at 148.872702 -406.370536)
		(size 0.4572)
		(drill 0.254)
		(layers "F.Cu" "B.Cu")
		(net "GND")
	)
	(via
		(at 194.193414 -230.466646)
		(size 0.4572)
		(drill 0.2032)
		(layers "F.Cu" "B.Cu")
		(net "GND")
	)
	(via
		(at 59.842146 -283.166566)
		(size 0.4572)
		(drill 0.2032)
		(layers "F.Cu" "B.Cu")
		(net "GND")
	)
	(via
		(at 90.494612 -230.086662)
		(size 0.4572)
		(drill 0.2032)
		(layers "F.Cu" "B.Cu")
		(net "GND")
	)
	(via
		(at 62.051946 -296.766742)
		(size 0.4572)
		(drill 0.2032)
		(layers "F.Cu" "B.Cu")
		(net "GND")
	)
	(via
		(at 285.150814 -311.216802)
		(size 0.4572)
		(drill 0.2032)
		(layers "F.Cu" "B.Cu")
		(net "GND")
	)
	(via
		(at 125.737366 -226.017328)
		(size 0.4572)
		(drill 0.2032)
		(layers "F.Cu" "B.Cu")
		(net "GND")
	)
	(via
		(at 124.327666 -226.831144)
		(size 0.4572)
		(drill 0.2032)
		(layers "F.Cu" "B.Cu")
		(net "GND")
	)
	(via
		(at 18.679414 -205.816708)
		(size 0.4572)
		(drill 0.2032)
		(layers "F.Cu" "B.Cu")
		(net "GND")
	)
	(via
		(at 49.666906 -12.37488)
		(size 0.508)
		(drill 0.254)
		(layers "F.Cu" "B.Cu")
		(net "GND")
	)
	(via
		(at 387.450584 -254.164592)
		(size 0.4572)
		(drill 0.2032)
		(layers "F.Cu" "B.Cu")
		(net "GND")
	)
	(via
		(at 391.411206 -156.613098)
		(size 0.508)
		(drill 0.254)
		(layers "F.Cu" "B.Cu")
		(net "GND")
	)
	(via
		(at 112.110266 -220.319854)
		(size 0.4572)
		(drill 0.2032)
		(layers "F.Cu" "B.Cu")
		(net "GND")
	)
	(via
		(at 157.975046 -404.51786)
		(size 0.4572)
		(drill 0.254)
		(layers "F.Cu" "B.Cu")
		(net "GND")
	)
	(via
		(at 44.279058 -58.655712)
		(size 0.508)
		(drill 0.254)
		(layers "F.Cu" "B.Cu")
		(net "GND")
	)
	(via
		(at 467.535514 -373.24538)
		(size 0.508)
		(drill 0.254)
		(layers "F.Cu" "B.Cu")
		(net "GND")
	)
	(via
		(at 327.250044 -437.49976)
		(size 0.4572)
		(drill 0.2032)
		(layers "F.Cu" "B.Cu")
		(net "GND")
	)
	(via
		(at 195.427346 -295.06672)
		(size 0.4572)
		(drill 0.2032)
		(layers "F.Cu" "B.Cu")
		(net "GND")
	)
	(via
		(at 194.193414 -301.01667)
		(size 0.4572)
		(drill 0.2032)
		(layers "F.Cu" "B.Cu")
		(net "GND")
	)
	(via
		(at 134.195566 -248.806208)
		(size 0.4572)
		(drill 0.2032)
		(layers "F.Cu" "B.Cu")
		(net "GND")
	)
	(via
		(at 370.858034 -245.55069)
		(size 0.4572)
		(drill 0.2032)
		(layers "F.Cu" "B.Cu")
		(net "GND")
	)
	(via
		(at 394.349986 -437.49976)
		(size 0.4572)
		(drill 0.2032)
		(layers "F.Cu" "B.Cu")
		(net "GND")
	)
	(via
		(at 394.173964 -441.225432)
		(size 0.508)
		(drill 0.254)
		(layers "F.Cu" "B.Cu")
		(net "GND")
	)
	(via
		(at 54.508146 -272.116804)
		(size 0.4572)
		(drill 0.2032)
		(layers "F.Cu" "B.Cu")
		(net "GND")
	)
	(via
		(at 294.904414 -287.416748)
		(size 0.4572)
		(drill 0.2032)
		(layers "F.Cu" "B.Cu")
		(net "GND")
	)
	(via
		(at 428.279814 -317.166752)
		(size 0.4572)
		(drill 0.2032)
		(layers "F.Cu" "B.Cu")
		(net "GND")
	)
	(via
		(at 378.92736 -330.313538)
		(size 0.508)
		(drill 0.254)
		(layers "F.Cu" "B.Cu")
		(net "GND")
	)
	(via
		(at 210.514946 -300.166786)
		(size 0.4572)
		(drill 0.2032)
		(layers "F.Cu" "B.Cu")
		(net "GND")
	)
	(via
		(at 455.011282 -202.416664)
		(size 0.4572)
		(drill 0.2032)
		(layers "F.Cu" "B.Cu")
		(net "GND")
	)
	(via
		(at 100.942648 -271.011396)
		(size 0.4572)
		(drill 0.2032)
		(layers "F.Cu" "B.Cu")
		(net "GND")
	)
	(via
		(at 432.379882 -278.916638)
		(size 0.4572)
		(drill 0.2032)
		(layers "F.Cu" "B.Cu")
		(net "GND")
	)
	(via
		(at 186.649614 -286.56661)
		(size 0.4572)
		(drill 0.2032)
		(layers "F.Cu" "B.Cu")
		(net "GND")
	)
	(via
		(at 87.315294 -263.686544)
		(size 0.4318)
		(drill 0.2032)
		(layers "F.Cu" "B.Cu")
		(net "GND")
	)
	(via
		(at 291.460682 -221.116652)
		(size 0.4572)
		(drill 0.2032)
		(layers "F.Cu" "B.Cu")
		(net "GND")
	)
	(via
		(at 415.402014 -290.816792)
		(size 0.4572)
		(drill 0.2032)
		(layers "F.Cu" "B.Cu")
		(net "GND")
	)
	(via
		(at 137.870692 -51.472084)
		(size 0.508)
		(drill 0.254)
		(layers "F.Cu" "B.Cu")
		(net "GND")
	)
	(via
		(at 443.23 -76.164948)
		(size 0.508)
		(drill 0.254)
		(layers "F.Cu" "B.Cu")
		(net "GND")
	)
	(via
		(at 78.250034 -436.051198)
		(size 0.4572)
		(drill 0.2032)
		(layers "F.Cu" "B.Cu")
		(net "GND")
	)
	(via
		(at 37.210746 -203.266802)
		(size 0.4572)
		(drill 0.2032)
		(layers "F.Cu" "B.Cu")
		(net "GND")
	)
	(via
		(at 37.940234 -109.571282)
		(size 0.508)
		(drill 0.254)
		(layers "F.Cu" "B.Cu")
		(net "GND")
	)
	(via
		(at 63.942214 -211.766658)
		(size 0.4572)
		(drill 0.2032)
		(layers "F.Cu" "B.Cu")
		(net "GND")
	)
	(via
		(at 11.135614 -244.066568)
		(size 0.4572)
		(drill 0.2032)
		(layers "F.Cu" "B.Cu")
		(net "GND")
	)
	(via
		(at 386.812282 -77.517498)
		(size 0.508)
		(drill 0.254)
		(layers "F.Cu" "B.Cu")
		(net "GND")
	)
	(via
		(at 169.352214 -228.766624)
		(size 0.4572)
		(drill 0.2032)
		(layers "F.Cu" "B.Cu")
		(net "GND")
	)
	(via
		(at 49.755552 -147.592034)
		(size 0.508)
		(drill 0.254)
		(layers "F.Cu" "B.Cu")
		(net "GND")
	)
	(via
		(at 449.677282 -262.76681)
		(size 0.4572)
		(drill 0.2032)
		(layers "F.Cu" "B.Cu")
		(net "GND")
	)
	(via
		(at 354.490274 -180.240432)
		(size 0.508)
		(drill 0.254)
		(layers "F.Cu" "B.Cu")
		(net "GND")
	)
	(via
		(at 27.547062 -9.424924)
		(size 0.508)
		(drill 0.254)
		(layers "F.Cu" "B.Cu")
		(net "GND")
	)
	(via
		(at 49.939194 -6.090412)
		(size 0.508)
		(drill 0.254)
		(layers "F.Cu" "B.Cu")
		(net "GND")
	)
	(via
		(at 292.694614 -251.716794)
		(size 0.4572)
		(drill 0.2032)
		(layers "F.Cu" "B.Cu")
		(net "GND")
	)
	(via
		(at 164.232336 -288.317432)
		(size 0.4572)
		(drill 0.2032)
		(layers "F.Cu" "B.Cu")
		(net "GND")
	)
	(via
		(at 264.729214 -234.716574)
		(size 0.4572)
		(drill 0.2032)
		(layers "F.Cu" "B.Cu")
		(net "GND")
	)
	(via
		(at 346.063062 -287.28924)
		(size 0.4572)
		(drill 0.2032)
		(layers "F.Cu" "B.Cu")
		(net "GND")
	)
	(via
		(at 31.751778 -99.586034)
		(size 0.508)
		(drill 0.254)
		(layers "F.Cu" "B.Cu")
		(net "GND")
	)
	(via
		(at 345.48318 -230.900478)
		(size 0.4572)
		(drill 0.2032)
		(layers "F.Cu" "B.Cu")
		(net "GND")
	)
	(via
		(at 375.55678 -227.64496)
		(size 0.4572)
		(drill 0.2032)
		(layers "F.Cu" "B.Cu")
		(net "GND")
	)
	(via
		(at 446.676272 -20.243038)
		(size 0.508)
		(drill 0.254)
		(layers "F.Cu" "B.Cu")
		(net "GND")
	)
	(via
		(at 352.3361 -410.664152)
		(size 0.4572)
		(drill 0.254)
		(layers "F.Cu" "B.Cu")
		(net "GND")
	)
	(via
		(at 336.085434 -240.667286)
		(size 0.4572)
		(drill 0.2032)
		(layers "F.Cu" "B.Cu")
		(net "GND")
	)
	(via
		(at 201.97826 -75.837288)
		(size 0.508)
		(drill 0.254)
		(layers "F.Cu" "B.Cu")
		(net "GND")
	)
	(via
		(at 279.262078 -416.27425)
		(size 0.508)
		(drill 0.254)
		(layers "F.Cu" "B.Cu")
		(net "GND")
	)
	(via
		(at 254.975614 -225.36658)
		(size 0.4572)
		(drill 0.2032)
		(layers "F.Cu" "B.Cu")
		(net "GND")
	)
	(via
		(at 261.577582 -69.231256)
		(size 0.508)
		(drill 0.254)
		(layers "F.Cu" "B.Cu")
		(net "GND")
	)
	(via
		(at 285.150814 -208.366614)
		(size 0.4572)
		(drill 0.2032)
		(layers "F.Cu" "B.Cu")
		(net "GND")
	)
	(via
		(at 37.210746 -210.916774)
		(size 0.4572)
		(drill 0.2032)
		(layers "F.Cu" "B.Cu")
		(net "GND")
	)
	(via
		(at 380.256034 -229.272846)
		(size 0.4572)
		(drill 0.2032)
		(layers "F.Cu" "B.Cu")
		(net "GND")
	)
	(via
		(at 302.637444 -360.143298)
		(size 0.508)
		(drill 0.254)
		(layers "F.Cu" "B.Cu")
		(net "GND")
	)
	(via
		(at 416.575494 -162.432238)
		(size 0.49022)
		(drill 0.254)
		(layers "F.Cu" "B.Cu")
		(net "GND")
	)
	(via
		(at 347.473016 -255.547622)
		(size 0.4572)
		(drill 0.2032)
		(layers "F.Cu" "B.Cu")
		(net "GND")
	)
	(via
		(at 319.25006 -426.69968)
		(size 0.4572)
		(drill 0.2032)
		(layers "F.Cu" "B.Cu")
		(net "GND")
	)
	(via
		(at 145.722086 -403.249892)
		(size 0.4572)
		(drill 0.254)
		(layers "F.Cu" "B.Cu")
		(net "GND")
	)
	(via
		(at 89.664794 -254.733552)
		(size 0.4572)
		(drill 0.2032)
		(layers "F.Cu" "B.Cu")
		(net "GND")
	)
	(via
		(at 48.854614 -316.316614)
		(size 0.4572)
		(drill 0.2032)
		(layers "F.Cu" "B.Cu")
		(net "GND")
	)
	(via
		(at 435.823614 -208.366614)
		(size 0.4572)
		(drill 0.2032)
		(layers "F.Cu" "B.Cu")
		(net "GND")
	)
	(via
		(at 315.250068 -436.347362)
		(size 0.4572)
		(drill 0.2032)
		(layers "F.Cu" "B.Cu")
		(net "GND")
	)
	(via
		(at 210.514946 -233.016806)
		(size 0.4572)
		(drill 0.2032)
		(layers "F.Cu" "B.Cu")
		(net "GND")
	)
	(via
		(at 71.82993 -409.396184)
		(size 0.4572)
		(drill 0.254)
		(layers "F.Cu" "B.Cu")
		(net "GND")
	)
	(via
		(at 150.29688 -109.419898)
		(size 0.508)
		(drill 0.254)
		(layers "F.Cu" "B.Cu")
		(net "GND")
	)
	(via
		(at 389.563864 -77.954886)
		(size 0.508)
		(drill 0.254)
		(layers "F.Cu" "B.Cu")
		(net "GND")
	)
	(via
		(at 216.824814 -264.466578)
		(size 0.4572)
		(drill 0.2032)
		(layers "F.Cu" "B.Cu")
		(net "GND")
	)
	(via
		(at 304.338482 -224.516696)
		(size 0.4572)
		(drill 0.2032)
		(layers "F.Cu" "B.Cu")
		(net "GND")
	)
	(via
		(at 39.420546 -195.616576)
		(size 0.4572)
		(drill 0.2032)
		(layers "F.Cu" "B.Cu")
		(net "GND")
	)
	(via
		(at 338.544916 -262.872474)
		(size 0.4572)
		(drill 0.2032)
		(layers "F.Cu" "B.Cu")
		(net "GND")
	)
	(via
		(at 157.92196 -67.551808)
		(size 0.508)
		(drill 0.254)
		(layers "F.Cu" "B.Cu")
		(net "GND")
	)
	(via
		(at 350.9899 -404.51786)
		(size 0.4572)
		(drill 0.254)
		(layers "F.Cu" "B.Cu")
		(net "GND")
	)
	(via
		(at 338.966556 -335.980278)
		(size 0.49022)
		(drill 0.254)
		(layers "F.Cu" "B.Cu")
		(net "GND")
	)
	(via
		(at 296.794682 -233.86669)
		(size 0.4572)
		(drill 0.2032)
		(layers "F.Cu" "B.Cu")
		(net "GND")
	)
	(via
		(at 49.128426 -406.370536)
		(size 0.4572)
		(drill 0.254)
		(layers "F.Cu" "B.Cu")
		(net "GND")
	)
	(via
		(at 117.075458 -329.22972)
		(size 0.508)
		(drill 0.254)
		(layers "F.Cu" "B.Cu")
		(net "GND")
	)
	(via
		(at 444.852552 -323.429376)
		(size 0.4572)
		(drill 0.2032)
		(layers "F.Cu" "B.Cu")
		(net "GND")
	)
	(via
		(at 283.916882 -239.81664)
		(size 0.4572)
		(drill 0.2032)
		(layers "F.Cu" "B.Cu")
		(net "GND")
	)
	(via
		(at 447.467482 -207.51673)
		(size 0.4572)
		(drill 0.2032)
		(layers "F.Cu" "B.Cu")
		(net "GND")
	)
	(via
		(at 14.579346 -208.366614)
		(size 0.4572)
		(drill 0.2032)
		(layers "F.Cu" "B.Cu")
		(net "GND")
	)
	(via
		(at 393.32662 -6.07949)
		(size 0.508)
		(drill 0.254)
		(layers "F.Cu" "B.Cu")
		(net "GND")
	)
	(via
		(at 125.737366 -216.25052)
		(size 0.4572)
		(drill 0.2032)
		(layers "F.Cu" "B.Cu")
		(net "GND")
	)
	(via
		(at 276.373082 -244.066568)
		(size 0.4572)
		(drill 0.2032)
		(layers "F.Cu" "B.Cu")
		(net "GND")
	)
	(via
		(at 52.298346 -206.666592)
		(size 0.4572)
		(drill 0.2032)
		(layers "F.Cu" "B.Cu")
		(net "GND")
	)
	(via
		(at 302.448214 -221.96679)
		(size 0.4572)
		(drill 0.2032)
		(layers "F.Cu" "B.Cu")
		(net "GND")
	)
	(via
		(at 443.367414 -217.716608)
		(size 0.4572)
		(drill 0.2032)
		(layers "F.Cu" "B.Cu")
		(net "GND")
	)
	(via
		(at 214.615014 -286.56661)
		(size 0.4572)
		(drill 0.2032)
		(layers "F.Cu" "B.Cu")
		(net "GND")
	)
	(via
		(at 428.279814 -223.666558)
		(size 0.4572)
		(drill 0.2032)
		(layers "F.Cu" "B.Cu")
		(net "GND")
	)
	(via
		(at 172.795946 -301.866808)
		(size 0.4572)
		(drill 0.2032)
		(layers "F.Cu" "B.Cu")
		(net "GND")
	)
	(via
		(at 48.92167 -322.268596)
		(size 0.4572)
		(drill 0.2032)
		(layers "F.Cu" "B.Cu")
		(net "GND")
	)
	(via
		(at 373.207534 -217.064336)
		(size 0.4572)
		(drill 0.2032)
		(layers "F.Cu" "B.Cu")
		(net "GND")
	)
	(via
		(at 149.352 -35.794188)
		(size 0.508)
		(drill 0.254)
		(layers "F.Cu" "B.Cu")
		(net "GND")
	)
	(via
		(at 417.289742 -154.230324)
		(size 0.508)
		(drill 0.254)
		(layers "F.Cu" "B.Cu")
		(net "GND")
	)
	(via
		(at 216.7128 -75.555348)
		(size 0.508)
		(drill 0.254)
		(layers "F.Cu" "B.Cu")
		(net "GND")
	)
	(via
		(at 201.737214 -288.266632)
		(size 0.4572)
		(drill 0.2032)
		(layers "F.Cu" "B.Cu")
		(net "GND")
	)
	(via
		(at 277.607014 -231.316784)
		(size 0.4572)
		(drill 0.2032)
		(layers "F.Cu" "B.Cu")
		(net "GND")
	)
	(via
		(at 419.590474 -136.162034)
		(size 0.508)
		(drill 0.254)
		(layers "F.Cu" "B.Cu")
		(net "GND")
	)
	(via
		(at 14.040358 -336.821272)
		(size 0.508)
		(drill 0.254)
		(layers "F.Cu" "B.Cu")
		(net "GND")
	)
	(via
		(at 254.975614 -283.166566)
		(size 0.4572)
		(drill 0.2032)
		(layers "F.Cu" "B.Cu")
		(net "GND")
	)
	(via
		(at 407.858214 -315.46673)
		(size 0.4572)
		(drill 0.2032)
		(layers "F.Cu" "B.Cu")
		(net "GND")
	)
	(via
		(at 314.092082 -233.86669)
		(size 0.4572)
		(drill 0.2032)
		(layers "F.Cu" "B.Cu")
		(net "GND")
	)
	(via
		(at 262.519414 -309.51678)
		(size 0.4572)
		(drill 0.2032)
		(layers "F.Cu" "B.Cu")
		(net "GND")
	)
	(via
		(at 304.338482 -303.566576)
		(size 0.4572)
		(drill 0.2032)
		(layers "F.Cu" "B.Cu")
		(net "GND")
	)
	(via
		(at 428.279814 -307.816758)
		(size 0.4572)
		(drill 0.2032)
		(layers "F.Cu" "B.Cu")
		(net "GND")
	)
	(via
		(at 347.472762 -257.175254)
		(size 0.4572)
		(drill 0.2032)
		(layers "F.Cu" "B.Cu")
		(net "GND")
	)
	(via
		(at 384.594862 -271.011396)
		(size 0.4318)
		(drill 0.2032)
		(layers "F.Cu" "B.Cu")
		(net "GND")
	)
	(via
		(at 427.045882 -200.716642)
		(size 0.4572)
		(drill 0.2032)
		(layers "F.Cu" "B.Cu")
		(net "GND")
	)
	(via
		(at 266.619482 -244.066568)
		(size 0.4572)
		(drill 0.2032)
		(layers "F.Cu" "B.Cu")
		(net "GND")
	)
	(via
		(at 467.535514 -104.00538)
		(size 0.508)
		(drill 0.254)
		(layers "F.Cu" "B.Cu")
		(net "GND")
	)
	(via
		(at 405.349964 -433.747164)
		(size 0.4572)
		(drill 0.2032)
		(layers "F.Cu" "B.Cu")
		(net "GND")
	)
	(via
		(at 37.210746 -263.616694)
		(size 0.4572)
		(drill 0.2032)
		(layers "F.Cu" "B.Cu")
		(net "GND")
	)
	(via
		(at 110.23092 -239.85347)
		(size 0.4572)
		(drill 0.2032)
		(layers "F.Cu" "B.Cu")
		(net "GND")
	)
	(via
		(at 169.352214 -303.566576)
		(size 0.4572)
		(drill 0.2032)
		(layers "F.Cu" "B.Cu")
		(net "GND")
	)
	(via
		(at 24.332946 -267.016738)
		(size 0.4572)
		(drill 0.2032)
		(layers "F.Cu" "B.Cu")
		(net "GND")
	)
	(via
		(at 369.172744 -334.282034)
		(size 0.49022)
		(drill 0.254)
		(layers "F.Cu" "B.Cu")
		(net "GND")
	)
	(via
		(at 339.374734 -233.34218)
		(size 0.4572)
		(drill 0.2032)
		(layers "F.Cu" "B.Cu")
		(net "GND")
	)
	(via
		(at 335.255362 -258.80314)
		(size 0.4318)
		(drill 0.2032)
		(layers "F.Cu" "B.Cu")
		(net "GND")
	)
	(via
		(at 77.95641 -410.664152)
		(size 0.4572)
		(drill 0.254)
		(layers "F.Cu" "B.Cu")
		(net "GND")
	)
	(via
		(at 128.28397 -354.584254)
		(size 0.508)
		(drill 0.254)
		(layers "F.Cu" "B.Cu")
		(net "GND")
	)
	(via
		(at 178.289204 -54.299866)
		(size 0.508)
		(drill 0.254)
		(layers "F.Cu" "B.Cu")
		(net "GND")
	)
	(via
		(at 442.133482 -194.766692)
		(size 0.4572)
		(drill 0.2032)
		(layers "F.Cu" "B.Cu")
		(net "GND")
	)
	(via
		(at 151.59736 -11.468608)
		(size 0.508)
		(drill 0.254)
		(layers "F.Cu" "B.Cu")
		(net "GND")
	)
	(via
		(at 212.724746 -279.766776)
		(size 0.4572)
		(drill 0.2032)
		(layers "F.Cu" "B.Cu")
		(net "GND")
	)
	(via
		(at 113.629694 -283.219906)
		(size 0.4572)
		(drill 0.2032)
		(layers "F.Cu" "B.Cu")
		(net "GND")
	)
	(via
		(at 210.514946 -289.11677)
		(size 0.4572)
		(drill 0.2032)
		(layers "F.Cu" "B.Cu")
		(net "GND")
	)
	(via
		(at 421.748712 -367.681764)
		(size 0.508)
		(drill 0.254)
		(layers "F.Cu" "B.Cu")
		(net "GND")
	)
	(via
		(at 53.45049 -406.370536)
		(size 0.4572)
		(drill 0.254)
		(layers "F.Cu" "B.Cu")
		(net "GND")
	)
	(via
		(at 16.789146 -221.96679)
		(size 0.4572)
		(drill 0.2032)
		(layers "F.Cu" "B.Cu")
		(net "GND")
	)
	(via
		(at 64.4652 -130.901948)
		(size 0.508)
		(drill 0.254)
		(layers "F.Cu" "B.Cu")
		(net "GND")
	)
	(via
		(at 106.471466 -223.575626)
		(size 0.4572)
		(drill 0.2032)
		(layers "F.Cu" "B.Cu")
		(net "GND")
	)
	(via
		(at 147.349972 -429.147224)
		(size 0.4572)
		(drill 0.2032)
		(layers "F.Cu" "B.Cu")
		(net "GND")
	)
	(via
		(at 38.227508 -399.293334)
		(size 0.508)
		(drill 0.254)
		(layers "F.Cu" "B.Cu")
		(net "GND")
	)
	(via
		(at 413.192214 -246.616728)
		(size 0.4572)
		(drill 0.2032)
		(layers "F.Cu" "B.Cu")
		(net "GND")
	)
	(via
		(at 119.09933 -257.6957)
		(size 0.4572)
		(drill 0.2032)
		(layers "F.Cu" "B.Cu")
		(net "GND")
	)
	(via
		(at 447.467482 -267.866622)
		(size 0.4572)
		(drill 0.2032)
		(layers "F.Cu" "B.Cu")
		(net "GND")
	)
	(via
		(at 450.911214 -265.316716)
		(size 0.4572)
		(drill 0.2032)
		(layers "F.Cu" "B.Cu")
		(net "GND")
	)
	(via
		(at 289.250882 -261.066788)
		(size 0.4572)
		(drill 0.2032)
		(layers "F.Cu" "B.Cu")
		(net "GND")
	)
	(via
		(at 117.614446 -326.892412)
		(size 0.508)
		(drill 0.254)
		(layers "F.Cu" "B.Cu")
		(net "GND")
	)
	(via
		(at 377.865132 -73.572624)
		(size 0.508)
		(drill 0.254)
		(layers "F.Cu" "B.Cu")
		(net "GND")
	)
	(via
		(at 464.764882 -277.216616)
		(size 0.4572)
		(drill 0.2032)
		(layers "F.Cu" "B.Cu")
		(net "GND")
	)
	(via
		(at 172.795946 -231.316784)
		(size 0.4572)
		(drill 0.2032)
		(layers "F.Cu" "B.Cu")
		(net "GND")
	)
	(via
		(at 359.580434 -222.761556)
		(size 0.4572)
		(drill 0.2032)
		(layers "F.Cu" "B.Cu")
		(net "GND")
	)
	(via
		(at 88.805766 -335.187036)
		(size 0.49022)
		(drill 0.254)
		(layers "F.Cu" "B.Cu")
		(net "GND")
	)
	(via
		(at 164.018214 -245.76659)
		(size 0.4572)
		(drill 0.2032)
		(layers "F.Cu" "B.Cu")
		(net "GND")
	)
	(via
		(at 62.051946 -197.316598)
		(size 0.4572)
		(drill 0.2032)
		(layers "F.Cu" "B.Cu")
		(net "GND")
	)
	(via
		(at 225.468434 -123.909074)
		(size 0.508)
		(drill 0.254)
		(layers "F.Cu" "B.Cu")
		(net "GND")
	)
	(via
		(at 158.65094 -36.281868)
		(size 0.508)
		(drill 0.254)
		(layers "F.Cu" "B.Cu")
		(net "GND")
	)
	(via
		(at 37.180266 -17.61236)
		(size 0.508)
		(drill 0.254)
		(layers "F.Cu" "B.Cu")
		(net "GND")
	)
	(via
		(at 356.54996 -393.28725)
		(size 0.508)
		(drill 0.254)
		(layers "F.Cu" "B.Cu")
		(net "GND")
	)
	(via
		(at 13.345414 -204.116686)
		(size 0.4572)
		(drill 0.2032)
		(layers "F.Cu" "B.Cu")
		(net "GND")
	)
	(via
		(at 48.854614 -233.86669)
		(size 0.4572)
		(drill 0.2032)
		(layers "F.Cu" "B.Cu")
		(net "GND")
	)
	(via
		(at 292.694614 -210.916774)
		(size 0.4572)
		(drill 0.2032)
		(layers "F.Cu" "B.Cu")
		(net "GND")
	)
	(via
		(at 126.786894 -260.430772)
		(size 0.4572)
		(drill 0.2032)
		(layers "F.Cu" "B.Cu")
		(net "GND")
	)
	(via
		(at 192.475866 -353.22383)
		(size 0.508)
		(drill 0.254)
		(layers "F.Cu" "B.Cu")
		(net "GND")
	)
	(via
		(at 414.16478 -175.707548)
		(size 0.508)
		(drill 0.254)
		(layers "F.Cu" "B.Cu")
		(net "GND")
	)
	(via
		(at 205.180946 -204.96657)
		(size 0.4572)
		(drill 0.2032)
		(layers "F.Cu" "B.Cu")
		(net "GND")
	)
	(via
		(at 114.243612 -366.167924)
		(size 0.508)
		(drill 0.254)
		(layers "F.Cu" "B.Cu")
		(net "GND")
	)
	(via
		(at 256.667 -67.020948)
		(size 0.508)
		(drill 0.254)
		(layers "F.Cu" "B.Cu")
		(net "GND")
	)
	(via
		(at 338.90458 -230.900478)
		(size 0.4572)
		(drill 0.2032)
		(layers "F.Cu" "B.Cu")
		(net "GND")
	)
	(via
		(at 191.983614 -249.166634)
		(size 0.4572)
		(drill 0.2032)
		(layers "F.Cu" "B.Cu")
		(net "GND")
	)
	(via
		(at 294.904414 -240.666778)
		(size 0.4572)
		(drill 0.2032)
		(layers "F.Cu" "B.Cu")
		(net "GND")
	)
	(via
		(at 113.52022 -248.806462)
		(size 0.4572)
		(drill 0.2032)
		(layers "F.Cu" "B.Cu")
		(net "GND")
	)
	(via
		(at 171.708318 -345.64701)
		(size 0.508)
		(drill 0.254)
		(layers "F.Cu" "B.Cu")
		(net "GND")
	)
	(via
		(at 214.615014 -310.366664)
		(size 0.4572)
		(drill 0.2032)
		(layers "F.Cu" "B.Cu")
		(net "GND")
	)
	(via
		(at 7.035546 -292.516814)
		(size 0.4572)
		(drill 0.2032)
		(layers "F.Cu" "B.Cu")
		(net "GND")
	)
	(via
		(at 11.135614 -264.466578)
		(size 0.4572)
		(drill 0.2032)
		(layers "F.Cu" "B.Cu")
		(net "GND")
	)
	(via
		(at 76.971398 -400.858228)
		(size 0.4064)
		(drill 0.2032)
		(layers "F.Cu" "B.Cu")
		(net "GND")
	)
	(via
		(at 270.063214 -234.716574)
		(size 0.4572)
		(drill 0.2032)
		(layers "F.Cu" "B.Cu")
		(net "GND")
	)
	(via
		(at 107.347766 -332.570074)
		(size 0.49022)
		(drill 0.254)
		(layers "F.Cu" "B.Cu")
		(net "GND")
	)
	(via
		(at 180.339746 -220.266768)
		(size 0.4572)
		(drill 0.2032)
		(layers "F.Cu" "B.Cu")
		(net "GND")
	)
	(via
		(at 161.808414 -210.066636)
		(size 0.4572)
		(drill 0.2032)
		(layers "F.Cu" "B.Cu")
		(net "GND")
	)
	(via
		(at 170.671998 -352.404172)
		(size 0.49022)
		(drill 0.254)
		(layers "F.Cu" "B.Cu")
		(net "GND")
	)
	(via
		(at 87.785194 -271.011396)
		(size 0.4572)
		(drill 0.2032)
		(layers "F.Cu" "B.Cu")
		(net "GND")
	)
	(via
		(at 78.414626 -401.492212)
		(size 0.4572)
		(drill 0.254)
		(layers "F.Cu" "B.Cu")
		(net "GND")
	)
	(via
		(at 118.798594 -272.639282)
		(size 0.4572)
		(drill 0.2032)
		(layers "F.Cu" "B.Cu")
		(net "GND")
	)
	(via
		(at 157.708346 -304.416714)
		(size 0.4572)
		(drill 0.2032)
		(layers "F.Cu" "B.Cu")
		(net "GND")
	)
	(via
		(at 88.145366 -235.783882)
		(size 0.4572)
		(drill 0.2032)
		(layers "F.Cu" "B.Cu")
		(net "GND")
	)
	(via
		(at 131.955794 -280.778204)
		(size 0.4572)
		(drill 0.2032)
		(layers "F.Cu" "B.Cu")
		(net "GND")
	)
	(via
		(at 197.637146 -225.36658)
		(size 0.4572)
		(drill 0.2032)
		(layers "F.Cu" "B.Cu")
		(net "GND")
	)
	(via
		(at 442.133482 -235.566712)
		(size 0.4572)
		(drill 0.2032)
		(layers "F.Cu" "B.Cu")
		(net "GND")
	)
	(via
		(at 165.447726 -406.34666)
		(size 0.4572)
		(drill 0.254)
		(layers "F.Cu" "B.Cu")
		(net "GND")
	)
	(via
		(at 368.618262 -269.38351)
		(size 0.4572)
		(drill 0.2032)
		(layers "F.Cu" "B.Cu")
		(net "GND")
	)
	(via
		(at 181.47157 -358.534716)
		(size 0.508)
		(drill 0.254)
		(layers "F.Cu" "B.Cu")
		(net "GND")
	)
	(via
		(at 123.020582 -401.492212)
		(size 0.4572)
		(drill 0.254)
		(layers "F.Cu" "B.Cu")
		(net "GND")
	)
	(via
		(at 435.823614 -270.416782)
		(size 0.4572)
		(drill 0.2032)
		(layers "F.Cu" "B.Cu")
		(net "GND")
	)
	(via
		(at 222.07093 -41.620948)
		(size 0.508)
		(drill 0.254)
		(layers "F.Cu" "B.Cu")
		(net "GND")
	)
	(via
		(at 174.984664 -319.268856)
		(size 0.4572)
		(drill 0.2032)
		(layers "F.Cu" "B.Cu")
		(net "GND")
	)
	(via
		(at 296.794682 -211.766658)
		(size 0.4572)
		(drill 0.2032)
		(layers "F.Cu" "B.Cu")
		(net "GND")
	)
	(via
		(at 51.064414 -241.516662)
		(size 0.4572)
		(drill 0.2032)
		(layers "F.Cu" "B.Cu")
		(net "GND")
	)
	(via
		(at 136.349994 -430.147222)
		(size 0.4572)
		(drill 0.2032)
		(layers "F.Cu" "B.Cu")
		(net "GND")
	)
	(via
		(at 167.461946 -263.616694)
		(size 0.4572)
		(drill 0.2032)
		(layers "F.Cu" "B.Cu")
		(net "GND")
	)
	(via
		(at 124.327412 -249.620024)
		(size 0.4572)
		(drill 0.2032)
		(layers "F.Cu" "B.Cu")
		(net "GND")
	)
	(via
		(at 455.011282 -228.766624)
		(size 0.4572)
		(drill 0.2032)
		(layers "F.Cu" "B.Cu")
		(net "GND")
	)
	(via
		(at 157.708346 -307.816758)
		(size 0.4572)
		(drill 0.2032)
		(layers "F.Cu" "B.Cu")
		(net "GND")
	)
	(via
		(at 299.700188 -393.77239)
		(size 0.508)
		(drill 0.254)
		(layers "F.Cu" "B.Cu")
		(net "GND")
	)
	(via
		(at 212.724746 -233.016806)
		(size 0.4572)
		(drill 0.2032)
		(layers "F.Cu" "B.Cu")
		(net "GND")
	)
	(via
		(at 202.971146 -307.816758)
		(size 0.4572)
		(drill 0.2032)
		(layers "F.Cu" "B.Cu")
		(net "GND")
	)
	(via
		(at 143.34998 -436.347362)
		(size 0.4572)
		(drill 0.2032)
		(layers "F.Cu" "B.Cu")
		(net "GND")
	)
	(via
		(at 335.145634 -232.528364)
		(size 0.4572)
		(drill 0.2032)
		(layers "F.Cu" "B.Cu")
		(net "GND")
	)
	(via
		(at 306.764182 -312.91657)
		(size 0.4572)
		(drill 0.2032)
		(layers "F.Cu" "B.Cu")
		(net "GND")
	)
	(via
		(at 54.508146 -300.166786)
		(size 0.4572)
		(drill 0.2032)
		(layers "F.Cu" "B.Cu")
		(net "GND")
	)
	(via
		(at 366.159034 -232.528364)
		(size 0.4572)
		(drill 0.2032)
		(layers "F.Cu" "B.Cu")
		(net "GND")
	)
	(via
		(at 90.604594 -284.033722)
		(size 0.4572)
		(drill 0.2032)
		(layers "F.Cu" "B.Cu")
		(net "GND")
	)
	(via
		(at 22.123146 -210.916774)
		(size 0.4572)
		(drill 0.2032)
		(layers "F.Cu" "B.Cu")
		(net "GND")
	)
	(via
		(at 120.838214 -333.355188)
		(size 0.49022)
		(drill 0.254)
		(layers "F.Cu" "B.Cu")
		(net "GND")
	)
	(via
		(at 149.9489 -74.778108)
		(size 0.508)
		(drill 0.254)
		(layers "F.Cu" "B.Cu")
		(net "GND")
	)
	(via
		(at 455.011282 -310.366664)
		(size 0.4572)
		(drill 0.2032)
		(layers "F.Cu" "B.Cu")
		(net "GND")
	)
	(via
		(at 339.954362 -275.08073)
		(size 0.4572)
		(drill 0.2032)
		(layers "F.Cu" "B.Cu")
		(net "GND")
	)
	(via
		(at 138.534394 -284.033722)
		(size 0.4572)
		(drill 0.2032)
		(layers "F.Cu" "B.Cu")
		(net "GND")
	)
	(via
		(at 344.362532 -40.461692)
		(size 0.4572)
		(drill 0.2032)
		(layers "F.Cu" "B.Cu")
		(net "GND")
	)
	(via
		(at 340.894416 -276.708616)
		(size 0.4572)
		(drill 0.2032)
		(layers "F.Cu" "B.Cu")
		(net "GND")
	)
	(via
		(at 412.015686 -165.727126)
		(size 0.508)
		(drill 0.254)
		(layers "F.Cu" "B.Cu")
		(net "GND")
	)
	(via
		(at 392.209782 -407.638504)
		(size 0.4572)
		(drill 0.254)
		(layers "F.Cu" "B.Cu")
		(net "GND")
	)
	(via
		(at 401.399502 -407.638504)
		(size 0.4572)
		(drill 0.254)
		(layers "F.Cu" "B.Cu")
		(net "GND")
	)
	(via
		(at 24.332946 -300.166786)
		(size 0.4572)
		(drill 0.2032)
		(layers "F.Cu" "B.Cu")
		(net "GND")
	)
	(via
		(at 205.180946 -296.766742)
		(size 0.4572)
		(drill 0.2032)
		(layers "F.Cu" "B.Cu")
		(net "GND")
	)
	(via
		(at 22.123146 -204.96657)
		(size 0.4572)
		(drill 0.2032)
		(layers "F.Cu" "B.Cu")
		(net "GND")
	)
	(via
		(at 323.250052 -429.147224)
		(size 0.4572)
		(drill 0.2032)
		(layers "F.Cu" "B.Cu")
		(net "GND")
	)
	(via
		(at 380.365762 -283.219906)
		(size 0.4572)
		(drill 0.2032)
		(layers "F.Cu" "B.Cu")
		(net "GND")
	)
	(via
		(at 31.876746 -195.616576)
		(size 0.4572)
		(drill 0.2032)
		(layers "F.Cu" "B.Cu")
		(net "GND")
	)
	(via
		(at 216.824814 -245.76659)
		(size 0.4572)
		(drill 0.2032)
		(layers "F.Cu" "B.Cu")
		(net "GND")
	)
	(via
		(at 11.135614 -232.166668)
		(size 0.4572)
		(drill 0.2032)
		(layers "F.Cu" "B.Cu")
		(net "GND")
	)
	(via
		(at 26.223214 -228.766624)
		(size 0.4572)
		(drill 0.2032)
		(layers "F.Cu" "B.Cu")
		(net "GND")
	)
	(via
		(at 180.339746 -276.366732)
		(size 0.4572)
		(drill 0.2032)
		(layers "F.Cu" "B.Cu")
		(net "GND")
	)
	(via
		(at 349.352616 -257.175254)
		(size 0.4572)
		(drill 0.2032)
		(layers "F.Cu" "B.Cu")
		(net "GND")
	)
	(via
		(at 304.767488 -407.00452)
		(size 0.4064)
		(drill 0.2032)
		(layers "F.Cu" "B.Cu")
		(net "GND")
	)
	(via
		(at 125.737112 -235.783882)
		(size 0.4572)
		(drill 0.2032)
		(layers "F.Cu" "B.Cu")
		(net "GND")
	)
	(via
		(at 439.923682 -241.516662)
		(size 0.4572)
		(drill 0.2032)
		(layers "F.Cu" "B.Cu")
		(net "GND")
	)
	(via
		(at 348.549722 -177.065432)
		(size 0.508)
		(drill 0.254)
		(layers "F.Cu" "B.Cu")
		(net "GND")
	)
	(via
		(at 302.448214 -309.51678)
		(size 0.4572)
		(drill 0.2032)
		(layers "F.Cu" "B.Cu")
		(net "GND")
	)
	(via
		(at 51.064414 -278.916638)
		(size 0.4572)
		(drill 0.2032)
		(layers "F.Cu" "B.Cu")
		(net "GND")
	)
	(via
		(at 92.365322 -332.512924)
		(size 0.508)
		(drill 0.254)
		(layers "F.Cu" "B.Cu")
		(net "GND")
	)
	(via
		(at 343.604596 -403.249892)
		(size 0.4572)
		(drill 0.254)
		(layers "F.Cu" "B.Cu")
		(net "GND")
	)
	(via
		(at 40.280082 -19.13636)
		(size 0.508)
		(drill 0.254)
		(layers "F.Cu" "B.Cu")
		(net "GND")
	)
	(via
		(at 399.349976 -427.851316)
		(size 0.4572)
		(drill 0.2032)
		(layers "F.Cu" "B.Cu")
		(net "GND")
	)
	(via
		(at 419.502082 -230.466646)
		(size 0.4572)
		(drill 0.2032)
		(layers "F.Cu" "B.Cu")
		(net "GND")
	)
	(via
		(at 263.37641 -73.906126)
		(size 0.508)
		(drill 0.254)
		(layers "F.Cu" "B.Cu")
		(net "GND")
	)
	(via
		(at 185.755788 -109.375448)
		(size 0.4572)
		(drill 0.254)
		(layers "F.Cu" "B.Cu")
		(net "GND")
	)
	(via
		(at 190.093346 -289.11677)
		(size 0.4572)
		(drill 0.2032)
		(layers "F.Cu" "B.Cu")
		(net "GND")
	)
	(via
		(at 85.435694 -286.475424)
		(size 0.4572)
		(drill 0.2032)
		(layers "F.Cu" "B.Cu")
		(net "GND")
	)
	(via
		(at 439.923682 -306.96662)
		(size 0.4572)
		(drill 0.2032)
		(layers "F.Cu" "B.Cu")
		(net "GND")
	)
	(via
		(at 372.377462 -262.872474)
		(size 0.4572)
		(drill 0.2032)
		(layers "F.Cu" "B.Cu")
		(net "GND")
	)
	(via
		(at 300.238414 -199.01662)
		(size 0.4572)
		(drill 0.2032)
		(layers "F.Cu" "B.Cu")
		(net "GND")
	)
	(via
		(at 415.844482 -354.180394)
		(size 0.508)
		(drill 0.254)
		(layers "F.Cu" "B.Cu")
		(net "GND")
	)
	(via
		(at 109.46892 -33.698688)
		(size 0.508)
		(drill 0.254)
		(layers "F.Cu" "B.Cu")
		(net "GND")
	)
	(via
		(at 195.427346 -283.166566)
		(size 0.4572)
		(drill 0.2032)
		(layers "F.Cu" "B.Cu")
		(net "GND")
	)
	(via
		(at 268.829282 -289.966654)
		(size 0.4572)
		(drill 0.2032)
		(layers "F.Cu" "B.Cu")
		(net "GND")
	)
	(via
		(at 261.285482 -247.466612)
		(size 0.4572)
		(drill 0.2032)
		(layers "F.Cu" "B.Cu")
		(net "GND")
	)
	(via
		(at 44.754546 -311.216802)
		(size 0.4572)
		(drill 0.2032)
		(layers "F.Cu" "B.Cu")
		(net "GND")
	)
	(via
		(at 151.574754 -407.00452)
		(size 0.4064)
		(drill 0.2032)
		(layers "F.Cu" "B.Cu")
		(net "GND")
	)
	(via
		(at 58.608214 -213.46668)
		(size 0.4572)
		(drill 0.2032)
		(layers "F.Cu" "B.Cu")
		(net "GND")
	)
	(via
		(at 90.25001 -431.29962)
		(size 0.4572)
		(drill 0.2032)
		(layers "F.Cu" "B.Cu")
		(net "GND")
	)
	(via
		(at 332.697328 -40.931846)
		(size 0.4572)
		(drill 0.2032)
		(layers "F.Cu" "B.Cu")
		(net "GND")
	)
	(via
		(at 104.701594 -274.266914)
		(size 0.4572)
		(drill 0.2032)
		(layers "F.Cu" "B.Cu")
		(net "GND")
	)
	(via
		(at 419.502082 -245.76659)
		(size 0.4572)
		(drill 0.2032)
		(layers "F.Cu" "B.Cu")
		(net "GND")
	)
	(via
		(at 94.363794 -266.128246)
		(size 0.4572)
		(drill 0.2032)
		(layers "F.Cu" "B.Cu")
		(net "GND")
	)
	(via
		(at 181.755796 -116.575586)
		(size 0.4572)
		(drill 0.254)
		(layers "F.Cu" "B.Cu")
		(net "GND")
	)
	(via
		(at 127.342646 -404.51786)
		(size 0.4572)
		(drill 0.254)
		(layers "F.Cu" "B.Cu")
		(net "GND")
	)
	(via
		(at 354.61321 -356.943406)
		(size 0.508)
		(drill 0.254)
		(layers "F.Cu" "B.Cu")
		(net "GND")
	)
	(via
		(at 212.724746 -244.916706)
		(size 0.4572)
		(drill 0.2032)
		(layers "F.Cu" "B.Cu")
		(net "GND")
	)
	(via
		(at 413.192214 -265.316716)
		(size 0.4572)
		(drill 0.2032)
		(layers "F.Cu" "B.Cu")
		(net "GND")
	)
	(via
		(at 346.995496 -25.788366)
		(size 0.508)
		(drill 0.254)
		(layers "F.Cu" "B.Cu")
		(net "GND")
	)
	(via
		(at 44.754546 -244.916706)
		(size 0.4572)
		(drill 0.2032)
		(layers "F.Cu" "B.Cu")
		(net "GND")
	)
	(via
		(at 316.385956 -57.775348)
		(size 0.508)
		(drill 0.254)
		(layers "F.Cu" "B.Cu")
		(net "GND")
	)
	(via
		(at 370.38788 -247.992138)
		(size 0.4572)
		(drill 0.2032)
		(layers "F.Cu" "B.Cu")
		(net "GND")
	)
	(via
		(at 374.44172 -330.303378)
		(size 0.508)
		(drill 0.254)
		(layers "F.Cu" "B.Cu")
		(net "GND")
	)
	(via
		(at 130.7719 -42.784522)
		(size 0.508)
		(drill 0.254)
		(layers "F.Cu" "B.Cu")
		(net "GND")
	)
	(via
		(at 196.140832 -439.905394)
		(size 0.508)
		(drill 0.254)
		(layers "F.Cu" "B.Cu")
		(net "GND")
	)
	(via
		(at 202.971146 -272.116804)
		(size 0.4572)
		(drill 0.2032)
		(layers "F.Cu" "B.Cu")
		(net "GND")
	)
	(via
		(at 456.051666 -103.646224)
		(size 0.508)
		(drill 0.254)
		(layers "F.Cu" "B.Cu")
		(net "GND")
	)
	(via
		(at 159.918146 -311.216802)
		(size 0.4572)
		(drill 0.2032)
		(layers "F.Cu" "B.Cu")
		(net "GND")
	)
	(via
		(at 376.93854 -336.765392)
		(size 0.49022)
		(drill 0.254)
		(layers "F.Cu" "B.Cu")
		(net "GND")
	)
	(via
		(at 419.76294 -100.260658)
		(size 0.508)
		(drill 0.254)
		(layers "F.Cu" "B.Cu")
		(net "GND")
	)
	(via
		(at 257.185414 -227.066602)
		(size 0.4572)
		(drill 0.2032)
		(layers "F.Cu" "B.Cu")
		(net "GND")
	)
	(via
		(at 460.664814 -278.066754)
		(size 0.4572)
		(drill 0.2032)
		(layers "F.Cu" "B.Cu")
		(net "GND")
	)
	(via
		(at 317.250064 -431.29962)
		(size 0.4572)
		(drill 0.2032)
		(layers "F.Cu" "B.Cu")
		(net "GND")
	)
	(via
		(at 191.983614 -235.566712)
		(size 0.4572)
		(drill 0.2032)
		(layers "F.Cu" "B.Cu")
		(net "GND")
	)
	(via
		(at 354.991416 -275.08073)
		(size 0.4572)
		(drill 0.2032)
		(layers "F.Cu" "B.Cu")
		(net "GND")
	)
	(via
		(at 428.279814 -313.766708)
		(size 0.4572)
		(drill 0.2032)
		(layers "F.Cu" "B.Cu")
		(net "GND")
	)
	(via
		(at 347.473016 -270.19758)
		(size 0.4572)
		(drill 0.2032)
		(layers "F.Cu" "B.Cu")
		(net "GND")
	)
	(via
		(at 46.964346 -231.316784)
		(size 0.4572)
		(drill 0.2032)
		(layers "F.Cu" "B.Cu")
		(net "GND")
	)
	(via
		(at 304.338482 -271.266666)
		(size 0.4572)
		(drill 0.2032)
		(layers "F.Cu" "B.Cu")
		(net "GND")
	)
	(via
		(at 361.45978 -239.0394)
		(size 0.4572)
		(drill 0.2032)
		(layers "F.Cu" "B.Cu")
		(net "GND")
	)
	(via
		(at 270.063214 -289.11677)
		(size 0.4572)
		(drill 0.2032)
		(layers "F.Cu" "B.Cu")
		(net "GND")
	)
	(via
		(at 299.004482 -261.066788)
		(size 0.4572)
		(drill 0.2032)
		(layers "F.Cu" "B.Cu")
		(net "GND")
	)
	(via
		(at 190.093346 -265.316716)
		(size 0.4572)
		(drill 0.2032)
		(layers "F.Cu" "B.Cu")
		(net "GND")
	)
	(via
		(at 66.152014 -305.266598)
		(size 0.4572)
		(drill 0.2032)
		(layers "F.Cu" "B.Cu")
		(net "GND")
	)
	(via
		(at 137.484866 -225.203258)
		(size 0.4572)
		(drill 0.2032)
		(layers "F.Cu" "B.Cu")
		(net "GND")
	)
	(via
		(at 351.745804 -332.56601)
		(size 0.49022)
		(drill 0.254)
		(layers "F.Cu" "B.Cu")
		(net "GND")
	)
	(via
		(at 128.196594 -287.28924)
		(size 0.4572)
		(drill 0.2032)
		(layers "F.Cu" "B.Cu")
		(net "GND")
	)
	(via
		(at 89.664794 -266.128246)
		(size 0.4572)
		(drill 0.2032)
		(layers "F.Cu" "B.Cu")
		(net "GND")
	)
	(via
		(at 66.152014 -241.516662)
		(size 0.4572)
		(drill 0.2032)
		(layers "F.Cu" "B.Cu")
		(net "GND")
	)
	(via
		(at 362.039916 -275.8948)
		(size 0.4572)
		(drill 0.2032)
		(layers "F.Cu" "B.Cu")
		(net "GND")
	)
	(via
		(at 334.785462 -274.266914)
		(size 0.4318)
		(drill 0.2032)
		(layers "F.Cu" "B.Cu")
		(net "GND")
	)
	(via
		(at 302.75022 -361.860338)
		(size 0.508)
		(drill 0.254)
		(layers "F.Cu" "B.Cu")
		(net "GND")
	)
	(via
		(at 259.564632 -30.579568)
		(size 0.508)
		(drill 0.254)
		(layers "F.Cu" "B.Cu")
		(net "GND")
	)
	(via
		(at 420.097966 -153.554684)
		(size 0.49022)
		(drill 0.254)
		(layers "F.Cu" "B.Cu")
		(net "GND")
	)
	(via
		(at 412.990792 -359.366312)
		(size 0.508)
		(drill 0.254)
		(layers "F.Cu" "B.Cu")
		(net "GND")
	)
	(via
		(at 54.893718 -407.00452)
		(size 0.4064)
		(drill 0.2032)
		(layers "F.Cu" "B.Cu")
		(net "GND")
	)
	(via
		(at 462.555082 -244.066568)
		(size 0.4572)
		(drill 0.2032)
		(layers "F.Cu" "B.Cu")
		(net "GND")
	)
	(via
		(at 121.038112 -234.15625)
		(size 0.4572)
		(drill 0.2032)
		(layers "F.Cu" "B.Cu")
		(net "GND")
	)
	(via
		(at 354.411534 -230.086662)
		(size 0.4572)
		(drill 0.2032)
		(layers "F.Cu" "B.Cu")
		(net "GND")
	)
	(via
		(at 335.615534 -238.225584)
		(size 0.4572)
		(drill 0.2032)
		(layers "F.Cu" "B.Cu")
		(net "GND")
	)
	(via
		(at 339.954362 -260.430772)
		(size 0.4572)
		(drill 0.2032)
		(layers "F.Cu" "B.Cu")
		(net "GND")
	)
	(via
		(at 375.634758 -406.370536)
		(size 0.4572)
		(drill 0.254)
		(layers "F.Cu" "B.Cu")
		(net "GND")
	)
	(via
		(at 123.387612 -244.73662)
		(size 0.4572)
		(drill 0.2032)
		(layers "F.Cu" "B.Cu")
		(net "GND")
	)
	(via
		(at 335.255362 -262.058658)
		(size 0.4318)
		(drill 0.2032)
		(layers "F.Cu" "B.Cu")
		(net "GND")
	)
	(via
		(at 186.649614 -200.716642)
		(size 0.4572)
		(drill 0.2032)
		(layers "F.Cu" "B.Cu")
		(net "GND")
	)
	(via
		(at 99.422966 -248.806208)
		(size 0.4572)
		(drill 0.2032)
		(layers "F.Cu" "B.Cu")
		(net "GND")
	)
	(via
		(at 165.252146 -251.716794)
		(size 0.4572)
		(drill 0.2032)
		(layers "F.Cu" "B.Cu")
		(net "GND")
	)
	(via
		(at 259.075682 -215.166702)
		(size 0.4572)
		(drill 0.2032)
		(layers "F.Cu" "B.Cu")
		(net "GND")
	)
	(via
		(at 44.432728 -350.214438)
		(size 0.508)
		(drill 0.254)
		(layers "F.Cu" "B.Cu")
		(net "GND")
	)
	(via
		(at 6.302756 -60.063888)
		(size 0.508)
		(drill 0.254)
		(layers "F.Cu" "B.Cu")
		(net "GND")
	)
	(via
		(at 134.912354 -403.883876)
		(size 0.4064)
		(drill 0.2032)
		(layers "F.Cu" "B.Cu")
		(net "GND")
	)
	(via
		(at 76.250038 -427.851316)
		(size 0.4572)
		(drill 0.2032)
		(layers "F.Cu" "B.Cu")
		(net "GND")
	)
	(via
		(at 382.715516 -288.917126)
		(size 0.4572)
		(drill 0.2032)
		(layers "F.Cu" "B.Cu")
		(net "GND")
	)
	(via
		(at 96.33585 -409.396184)
		(size 0.4572)
		(drill 0.254)
		(layers "F.Cu" "B.Cu")
		(net "GND")
	)
	(via
		(at 240.2332 -111.607346)
		(size 0.508)
		(drill 0.254)
		(layers "F.Cu" "B.Cu")
		(net "GND")
	)
	(via
		(at 91.434666 -238.225584)
		(size 0.4572)
		(drill 0.2032)
		(layers "F.Cu" "B.Cu")
		(net "GND")
	)
	(via
		(at 363.281976 -237.149132)
		(size 0.4572)
		(drill 0.2032)
		(layers "F.Cu" "B.Cu")
		(net "GND")
	)
	(via
		(at 258.346194 -323.417946)
		(size 0.4572)
		(drill 0.2032)
		(layers "F.Cu" "B.Cu")
		(net "GND")
	)
	(via
		(at 11.135614 -289.966654)
		(size 0.4572)
		(drill 0.2032)
		(layers "F.Cu" "B.Cu")
		(net "GND")
	)
	(via
		(at 126.316994 -266.128246)
		(size 0.4572)
		(drill 0.2032)
		(layers "F.Cu" "B.Cu")
		(net "GND")
	)
	(via
		(at 434.589682 -213.46668)
		(size 0.4572)
		(drill 0.2032)
		(layers "F.Cu" "B.Cu")
		(net "GND")
	)
	(via
		(at 376.271536 -106.525568)
		(size 0.508)
		(drill 0.254)
		(layers "F.Cu" "B.Cu")
		(net "GND")
	)
	(via
		(at 28.638246 -392.326876)
		(size 0.508)
		(drill 0.254)
		(layers "F.Cu" "B.Cu")
		(net "GND")
	)
	(via
		(at 210.514946 -250.016772)
		(size 0.4572)
		(drill 0.2032)
		(layers "F.Cu" "B.Cu")
		(net "GND")
	)
	(via
		(at 250.992386 -103.903272)
		(size 0.508)
		(drill 0.254)
		(layers "F.Cu" "B.Cu")
		(net "GND")
	)
	(via
		(at 139.682982 -409.396184)
		(size 0.4572)
		(drill 0.254)
		(layers "F.Cu" "B.Cu")
		(net "GND")
	)
	(via
		(at 362.039662 -272.639282)
		(size 0.4572)
		(drill 0.2032)
		(layers "F.Cu" "B.Cu")
		(net "GND")
	)
	(via
		(at 190.093346 -296.766742)
		(size 0.4572)
		(drill 0.2032)
		(layers "F.Cu" "B.Cu")
		(net "GND")
	)
	(via
		(at 164.018214 -280.61666)
		(size 0.4572)
		(drill 0.2032)
		(layers "F.Cu" "B.Cu")
		(net "GND")
	)
	(via
		(at 51.706018 -6.597396)
		(size 0.508)
		(drill 0.254)
		(layers "F.Cu" "B.Cu")
		(net "GND")
	)
	(via
		(at 329.25004 -427.699678)
		(size 0.4572)
		(drill 0.2032)
		(layers "F.Cu" "B.Cu")
		(net "GND")
	)
	(via
		(at 197.637146 -199.01662)
		(size 0.4572)
		(drill 0.2032)
		(layers "F.Cu" "B.Cu")
		(net "GND")
	)
	(via
		(at 432.379882 -245.76659)
		(size 0.4572)
		(drill 0.2032)
		(layers "F.Cu" "B.Cu")
		(net "GND")
	)
	(via
		(at 431.36693 -7.215124)
		(size 0.508)
		(drill 0.254)
		(layers "F.Cu" "B.Cu")
		(net "GND")
	)
	(via
		(at 215.82634 -53.863748)
		(size 0.508)
		(drill 0.254)
		(layers "F.Cu" "B.Cu")
		(net "GND")
	)
	(via
		(at 78.317598 -407.00452)
		(size 0.4064)
		(drill 0.2032)
		(layers "F.Cu" "B.Cu")
		(net "GND")
	)
	(via
		(at 396.349982 -427.699678)
		(size 0.4572)
		(drill 0.2032)
		(layers "F.Cu" "B.Cu")
		(net "GND")
	)
	(via
		(at 94.723712 -234.15625)
		(size 0.4572)
		(drill 0.2032)
		(layers "F.Cu" "B.Cu")
		(net "GND")
	)
	(via
		(at 147.349972 -433.899564)
		(size 0.4572)
		(drill 0.2032)
		(layers "F.Cu" "B.Cu")
		(net "GND")
	)
	(via
		(at 121.978166 -216.25052)
		(size 0.4572)
		(drill 0.2032)
		(layers "F.Cu" "B.Cu")
		(net "GND")
	)
	(via
		(at 407.858214 -246.616728)
		(size 0.4572)
		(drill 0.2032)
		(layers "F.Cu" "B.Cu")
		(net "GND")
	)
	(via
		(at 22.123146 -273.816572)
		(size 0.4572)
		(drill 0.2032)
		(layers "F.Cu" "B.Cu")
		(net "GND")
	)
	(via
		(at 409.748482 -228.766624)
		(size 0.4572)
		(drill 0.2032)
		(layers "F.Cu" "B.Cu")
		(net "GND")
	)
	(via
		(at 130.27533 -441.225432)
		(size 0.508)
		(drill 0.254)
		(layers "F.Cu" "B.Cu")
		(net "GND")
	)
	(via
		(at 264.729214 -300.166786)
		(size 0.4572)
		(drill 0.2032)
		(layers "F.Cu" "B.Cu")
		(net "GND")
	)
	(via
		(at 24.332946 -246.616728)
		(size 0.4572)
		(drill 0.2032)
		(layers "F.Cu" "B.Cu")
		(net "GND")
	)
	(via
		(at 202.971146 -289.11677)
		(size 0.4572)
		(drill 0.2032)
		(layers "F.Cu" "B.Cu")
		(net "GND")
	)
	(via
		(at 52.298346 -231.316784)
		(size 0.4572)
		(drill 0.2032)
		(layers "F.Cu" "B.Cu")
		(net "GND")
	)
	(via
		(at 268.829282 -277.216616)
		(size 0.4572)
		(drill 0.2032)
		(layers "F.Cu" "B.Cu")
		(net "GND")
	)
	(via
		(at 66.367914 -219.41663)
		(size 0.4572)
		(drill 0.2032)
		(layers "F.Cu" "B.Cu")
		(net "GND")
	)
	(via
		(at 337.495134 -247.992138)
		(size 0.4572)
		(drill 0.2032)
		(layers "F.Cu" "B.Cu")
		(net "GND")
	)
	(via
		(at 135.605266 -228.45903)
		(size 0.4572)
		(drill 0.2032)
		(layers "F.Cu" "B.Cu")
		(net "GND")
	)
	(via
		(at 50.845466 -403.249892)
		(size 0.4572)
		(drill 0.254)
		(layers "F.Cu" "B.Cu")
		(net "GND")
	)
	(via
		(at 164.018214 -196.466714)
		(size 0.4572)
		(drill 0.2032)
		(layers "F.Cu" "B.Cu")
		(net "GND")
	)
	(via
		(at 259.075682 -226.216718)
		(size 0.4572)
		(drill 0.2032)
		(layers "F.Cu" "B.Cu")
		(net "GND")
	)
	(via
		(at 377.322842 -342.270334)
		(size 0.508)
		(drill 0.254)
		(layers "F.Cu" "B.Cu")
		(net "GND")
	)
	(via
		(at 355.930962 -279.964134)
		(size 0.4572)
		(drill 0.2032)
		(layers "F.Cu" "B.Cu")
		(net "GND")
	)
	(via
		(at 29.666692 -406.037288)
		(size 0.508)
		(drill 0.254)
		(layers "F.Cu" "B.Cu")
		(net "GND")
	)
	(via
		(at 382.60528 -220.319854)
		(size 0.4572)
		(drill 0.2032)
		(layers "F.Cu" "B.Cu")
		(net "GND")
	)
	(via
		(at 56.182514 -312.91657)
		(size 0.4572)
		(drill 0.2032)
		(layers "F.Cu" "B.Cu")
		(net "GND")
	)
	(via
		(at 127.627126 -335.187036)
		(size 0.49022)
		(drill 0.254)
		(layers "F.Cu" "B.Cu")
		(net "GND")
	)
	(via
		(at 430.489614 -265.316716)
		(size 0.4572)
		(drill 0.2032)
		(layers "F.Cu" "B.Cu")
		(net "GND")
	)
	(via
		(at 16.733774 -77.578204)
		(size 0.508)
		(drill 0.254)
		(layers "F.Cu" "B.Cu")
		(net "GND")
	)
	(via
		(at 334.25003 -432.451256)
		(size 0.4572)
		(drill 0.2032)
		(layers "F.Cu" "B.Cu")
		(net "GND")
	)
	(via
		(at 63.942214 -258.516628)
		(size 0.4572)
		(drill 0.2032)
		(layers "F.Cu" "B.Cu")
		(net "GND")
	)
	(via
		(at 123.027694 -258.80314)
		(size 0.4572)
		(drill 0.2032)
		(layers "F.Cu" "B.Cu")
		(net "GND")
	)
	(via
		(at 159.918146 -250.016772)
		(size 0.4572)
		(drill 0.2032)
		(layers "F.Cu" "B.Cu")
		(net "GND")
	)
	(via
		(at 134.305548 -276.708616)
		(size 0.4572)
		(drill 0.2032)
		(layers "F.Cu" "B.Cu")
		(net "GND")
	)
	(via
		(at 408.96921 -410.030168)
		(size 0.4064)
		(drill 0.2032)
		(layers "F.Cu" "B.Cu")
		(net "GND")
	)
	(via
		(at 442.133482 -294.216582)
		(size 0.4572)
		(drill 0.2032)
		(layers "F.Cu" "B.Cu")
		(net "GND")
	)
	(via
		(at 387.30428 -236.597952)
		(size 0.4572)
		(drill 0.2032)
		(layers "F.Cu" "B.Cu")
		(net "GND")
	)
	(via
		(at 157.708346 -281.466798)
		(size 0.4572)
		(drill 0.2032)
		(layers "F.Cu" "B.Cu")
		(net "GND")
	)
	(via
		(at 195.427346 -216.016586)
		(size 0.4572)
		(drill 0.2032)
		(layers "F.Cu" "B.Cu")
		(net "GND")
	)
	(via
		(at 277.607014 -208.366614)
		(size 0.4572)
		(drill 0.2032)
		(layers "F.Cu" "B.Cu")
		(net "GND")
	)
	(via
		(at 306.63388 -62.775592)
		(size 0.508)
		(drill 0.254)
		(layers "F.Cu" "B.Cu")
		(net "GND")
	)
	(via
		(at 182.549546 -248.31675)
		(size 0.4572)
		(drill 0.2032)
		(layers "F.Cu" "B.Cu")
		(net "GND")
	)
	(via
		(at 378.84608 -234.970066)
		(size 0.4572)
		(drill 0.2032)
		(layers "F.Cu" "B.Cu")
		(net "GND")
	)
	(via
		(at 354.7364 -401.955)
		(size 0.508)
		(drill 0.254)
		(layers "F.Cu" "B.Cu")
		(net "GND")
	)
	(via
		(at 145.349976 -432.451256)
		(size 0.4572)
		(drill 0.2032)
		(layers "F.Cu" "B.Cu")
		(net "GND")
	)
	(via
		(at 173.86808 -38.730428)
		(size 0.508)
		(drill 0.254)
		(layers "F.Cu" "B.Cu")
		(net "GND")
	)
	(via
		(at 176.896014 -282.316682)
		(size 0.4572)
		(drill 0.2032)
		(layers "F.Cu" "B.Cu")
		(net "GND")
	)
	(via
		(at 283.916882 -228.766624)
		(size 0.4572)
		(drill 0.2032)
		(layers "F.Cu" "B.Cu")
		(net "GND")
	)
	(via
		(at 401.399502 -406.370536)
		(size 0.4572)
		(drill 0.254)
		(layers "F.Cu" "B.Cu")
		(net "GND")
	)
	(via
		(at 176.896014 -194.766692)
		(size 0.4572)
		(drill 0.2032)
		(layers "F.Cu" "B.Cu")
		(net "GND")
	)
	(via
		(at 262.001508 -67.904868)
		(size 0.508)
		(drill 0.254)
		(layers "F.Cu" "B.Cu")
		(net "GND")
	)
	(via
		(at 44.754546 -260.21665)
		(size 0.4572)
		(drill 0.2032)
		(layers "F.Cu" "B.Cu")
		(net "GND")
	)
	(via
		(at 290.983162 -18.714466)
		(size 0.508)
		(drill 0.254)
		(layers "F.Cu" "B.Cu")
		(net "GND")
	)
	(via
		(at 272.273014 -287.416748)
		(size 0.4572)
		(drill 0.2032)
		(layers "F.Cu" "B.Cu")
		(net "GND")
	)
	(via
		(at 413.192214 -227.066602)
		(size 0.4572)
		(drill 0.2032)
		(layers "F.Cu" "B.Cu")
		(net "GND")
	)
	(via
		(at 136.184894 -281.59202)
		(size 0.4572)
		(drill 0.2032)
		(layers "F.Cu" "B.Cu")
		(net "GND")
	)
	(via
		(at 33.767014 -213.46668)
		(size 0.4572)
		(drill 0.2032)
		(layers "F.Cu" "B.Cu")
		(net "GND")
	)
	(via
		(at 211.380832 -439.905394)
		(size 0.508)
		(drill 0.254)
		(layers "F.Cu" "B.Cu")
		(net "GND")
	)
	(via
		(at 344.25001 -426.69968)
		(size 0.4572)
		(drill 0.2032)
		(layers "F.Cu" "B.Cu")
		(net "GND")
	)
	(via
		(at 333.46263 -82.490056)
		(size 0.508)
		(drill 0.254)
		(layers "F.Cu" "B.Cu")
		(net "GND")
	)
	(via
		(at 113.519966 -229.272846)
		(size 0.4572)
		(drill 0.2032)
		(layers "F.Cu" "B.Cu")
		(net "GND")
	)
	(via
		(at 405.42337 -4.95173)
		(size 0.508)
		(drill 0.254)
		(layers "F.Cu" "B.Cu")
		(net "GND")
	)
	(via
		(at 455.011282 -221.116652)
		(size 0.4572)
		(drill 0.2032)
		(layers "F.Cu" "B.Cu")
		(net "GND")
	)
	(via
		(at 384.124962 -266.941808)
		(size 0.4572)
		(drill 0.2032)
		(layers "F.Cu" "B.Cu")
		(net "GND")
	)
	(via
		(at 294.904414 -208.366614)
		(size 0.4572)
		(drill 0.2032)
		(layers "F.Cu" "B.Cu")
		(net "GND")
	)
	(via
		(at 39.420546 -214.316564)
		(size 0.4572)
		(drill 0.2032)
		(layers "F.Cu" "B.Cu")
		(net "GND")
	)
	(via
		(at 119.705628 -263.277604)
		(size 0.4572)
		(drill 0.2032)
		(layers "F.Cu" "B.Cu")
		(net "GND")
	)
	(via
		(at 424.836082 -286.56661)
		(size 0.4572)
		(drill 0.2032)
		(layers "F.Cu" "B.Cu")
		(net "GND")
	)
	(via
		(at 169.132504 -210.066636)
		(size 0.4572)
		(drill 0.2032)
		(layers "F.Cu" "B.Cu")
		(net "GND")
	)
	(via
		(at 229.61092 -57.030366)
		(size 0.508)
		(drill 0.254)
		(layers "F.Cu" "B.Cu")
		(net "GND")
	)
	(via
		(at 421.89146 -358.754172)
		(size 0.508)
		(drill 0.254)
		(layers "F.Cu" "B.Cu")
		(net "GND")
	)
	(via
		(at 436.597552 -323.429376)
		(size 0.4572)
		(drill 0.2032)
		(layers "F.Cu" "B.Cu")
		(net "GND")
	)
	(via
		(at 201.737214 -303.566576)
		(size 0.4572)
		(drill 0.2032)
		(layers "F.Cu" "B.Cu")
		(net "GND")
	)
	(via
		(at 294.91051 -319.753234)
		(size 0.4572)
		(drill 0.2032)
		(layers "F.Cu" "B.Cu")
		(net "GND")
	)
	(via
		(at 159.918146 -287.416748)
		(size 0.4572)
		(drill 0.2032)
		(layers "F.Cu" "B.Cu")
		(net "GND")
	)
	(via
		(at 124.279406 -401.492212)
		(size 0.4572)
		(drill 0.254)
		(layers "F.Cu" "B.Cu")
		(net "GND")
	)
	(via
		(at 294.904414 -292.516814)
		(size 0.4572)
		(drill 0.2032)
		(layers "F.Cu" "B.Cu")
		(net "GND")
	)
	(via
		(at 277.607014 -238.966756)
		(size 0.4572)
		(drill 0.2032)
		(layers "F.Cu" "B.Cu")
		(net "GND")
	)
	(via
		(at 120.098566 -216.25052)
		(size 0.4572)
		(drill 0.2032)
		(layers "F.Cu" "B.Cu")
		(net "GND")
	)
	(via
		(at 96.243394 -287.28924)
		(size 0.4572)
		(drill 0.2032)
		(layers "F.Cu" "B.Cu")
		(net "GND")
	)
	(via
		(at 314.307982 -238.116618)
		(size 0.4572)
		(drill 0.2032)
		(layers "F.Cu" "B.Cu")
		(net "GND")
	)
	(via
		(at 344.07348 -234.970066)
		(size 0.4572)
		(drill 0.2032)
		(layers "F.Cu" "B.Cu")
		(net "GND")
	)
	(via
		(at 300.238414 -260.21665)
		(size 0.4572)
		(drill 0.2032)
		(layers "F.Cu" "B.Cu")
		(net "GND")
	)
	(via
		(at 194.193414 -204.116686)
		(size 0.4572)
		(drill 0.2032)
		(layers "F.Cu" "B.Cu")
		(net "GND")
	)
	(via
		(at 45.179234 -112.619282)
		(size 0.508)
		(drill 0.254)
		(layers "F.Cu" "B.Cu")
		(net "GND")
	)
	(via
		(at 129.608326 -335.976214)
		(size 0.49022)
		(drill 0.254)
		(layers "F.Cu" "B.Cu")
		(net "GND")
	)
	(via
		(at 160.178242 -301.866808)
		(size 0.4572)
		(drill 0.2032)
		(layers "F.Cu" "B.Cu")
		(net "GND")
	)
	(via
		(at 411.349952 -430.299622)
		(size 0.4572)
		(drill 0.2032)
		(layers "F.Cu" "B.Cu")
		(net "GND")
	)
	(via
		(at 304.338482 -262.76681)
		(size 0.4572)
		(drill 0.2032)
		(layers "F.Cu" "B.Cu")
		(net "GND")
	)
	(via
		(at 98.123248 -269.38351)
		(size 0.4572)
		(drill 0.2032)
		(layers "F.Cu" "B.Cu")
		(net "GND")
	)
	(via
		(at 50.996596 -355.531928)
		(size 0.49022)
		(drill 0.254)
		(layers "F.Cu" "B.Cu")
		(net "GND")
	)
	(via
		(at 129.026666 -213.732618)
		(size 0.4572)
		(drill 0.2032)
		(layers "F.Cu" "B.Cu")
		(net "GND")
	)
	(via
		(at 107.051348 -281.59202)
		(size 0.4572)
		(drill 0.2032)
		(layers "F.Cu" "B.Cu")
		(net "GND")
	)
	(via
		(at 62.051946 -246.616728)
		(size 0.4572)
		(drill 0.2032)
		(layers "F.Cu" "B.Cu")
		(net "GND")
	)
	(via
		(at 272.273014 -203.266802)
		(size 0.4572)
		(drill 0.2032)
		(layers "F.Cu" "B.Cu")
		(net "GND")
	)
	(via
		(at 259.075682 -271.266666)
		(size 0.4572)
		(drill 0.2032)
		(layers "F.Cu" "B.Cu")
		(net "GND")
	)
	(via
		(at 432.379882 -295.916604)
		(size 0.4572)
		(drill 0.2032)
		(layers "F.Cu" "B.Cu")
		(net "GND")
	)
	(via
		(at 126.653544 -74.453242)
		(size 0.508)
		(drill 0.254)
		(layers "F.Cu" "B.Cu")
		(net "GND")
	)
	(via
		(at 457.221082 -249.166634)
		(size 0.4572)
		(drill 0.2032)
		(layers "F.Cu" "B.Cu")
		(net "GND")
	)
	(via
		(at 377.076462 -279.150318)
		(size 0.4572)
		(drill 0.2032)
		(layers "F.Cu" "B.Cu")
		(net "GND")
	)
	(via
		(at 91.434666 -233.34218)
		(size 0.4572)
		(drill 0.2032)
		(layers "F.Cu" "B.Cu")
		(net "GND")
	)
	(via
		(at 277.607014 -317.166752)
		(size 0.4572)
		(drill 0.2032)
		(layers "F.Cu" "B.Cu")
		(net "GND")
	)
	(via
		(at 51.064414 -267.866622)
		(size 0.4572)
		(drill 0.2032)
		(layers "F.Cu" "B.Cu")
		(net "GND")
	)
	(via
		(at 149.349968 -428.851314)
		(size 0.4572)
		(drill 0.2032)
		(layers "F.Cu" "B.Cu")
		(net "GND")
	)
	(via
		(at 300.238414 -246.616728)
		(size 0.4572)
		(drill 0.2032)
		(layers "F.Cu" "B.Cu")
		(net "GND")
	)
	(via
		(at 268.829282 -297.616626)
		(size 0.4572)
		(drill 0.2032)
		(layers "F.Cu" "B.Cu")
		(net "GND")
	)
	(via
		(at 87.205312 -243.922804)
		(size 0.4318)
		(drill 0.2032)
		(layers "F.Cu" "B.Cu")
		(net "GND")
	)
	(via
		(at 35.976814 -297.616626)
		(size 0.4572)
		(drill 0.2032)
		(layers "F.Cu" "B.Cu")
		(net "GND")
	)
	(via
		(at 190.093346 -258.516628)
		(size 0.4572)
		(drill 0.2032)
		(layers "F.Cu" "B.Cu")
		(net "GND")
	)
	(via
		(at 202.971146 -203.266802)
		(size 0.4572)
		(drill 0.2032)
		(layers "F.Cu" "B.Cu")
		(net "GND")
	)
	(via
		(at 377.546616 -266.941808)
		(size 0.4572)
		(drill 0.2032)
		(layers "F.Cu" "B.Cu")
		(net "GND")
	)
	(via
		(at 84.444078 -410.030168)
		(size 0.4064)
		(drill 0.2032)
		(layers "F.Cu" "B.Cu")
		(net "GND")
	)
	(via
		(at 37.860732 -0.76454)
		(size 0.508)
		(drill 0.254)
		(layers "F.Cu" "B.Cu")
		(net "GND")
	)
	(via
		(at 56.050942 -18.246344)
		(size 0.508)
		(drill 0.254)
		(layers "F.Cu" "B.Cu")
		(net "GND")
	)
	(via
		(at 438.853072 -0.76454)
		(size 0.508)
		(drill 0.254)
		(layers "F.Cu" "B.Cu")
		(net "GND")
	)
	(via
		(at 118.328694 -279.964134)
		(size 0.4572)
		(drill 0.2032)
		(layers "F.Cu" "B.Cu")
		(net "GND")
	)
	(via
		(at 428.046642 -6.07949)
		(size 0.508)
		(drill 0.254)
		(layers "F.Cu" "B.Cu")
		(net "GND")
	)
	(via
		(at 130.076194 -267.755878)
		(size 0.4572)
		(drill 0.2032)
		(layers "F.Cu" "B.Cu")
		(net "GND")
	)
	(via
		(at 184.439814 -244.066568)
		(size 0.4572)
		(drill 0.2032)
		(layers "F.Cu" "B.Cu")
		(net "GND")
	)
	(via
		(at 429.299624 -16.967454)
		(size 0.508)
		(drill 0.254)
		(layers "F.Cu" "B.Cu")
		(net "GND")
	)
	(via
		(at 201.737214 -297.616626)
		(size 0.4572)
		(drill 0.2032)
		(layers "F.Cu" "B.Cu")
		(net "GND")
	)
	(via
		(at 306.548282 -249.166634)
		(size 0.4572)
		(drill 0.2032)
		(layers "F.Cu" "B.Cu")
		(net "GND")
	)
	(via
		(at 346.250006 -436.051198)
		(size 0.4572)
		(drill 0.2032)
		(layers "F.Cu" "B.Cu")
		(net "GND")
	)
	(via
		(at 413.50438 -176.367948)
		(size 0.508)
		(drill 0.254)
		(layers "F.Cu" "B.Cu")
		(net "GND")
	)
	(via
		(at 336.555334 -225.203258)
		(size 0.4572)
		(drill 0.2032)
		(layers "F.Cu" "B.Cu")
		(net "GND")
	)
	(via
		(at 262.519414 -221.96679)
		(size 0.4572)
		(drill 0.2032)
		(layers "F.Cu" "B.Cu")
		(net "GND")
	)
	(via
		(at 351.71253 -361.961938)
		(size 0.508)
		(drill 0.254)
		(layers "F.Cu" "B.Cu")
		(net "GND")
	)
	(via
		(at 361.569762 -270.19758)
		(size 0.4572)
		(drill 0.2032)
		(layers "F.Cu" "B.Cu")
		(net "GND")
	)
	(via
		(at 453.121014 -260.21665)
		(size 0.4572)
		(drill 0.2032)
		(layers "F.Cu" "B.Cu")
		(net "GND")
	)
	(via
		(at 9.245346 -210.916774)
		(size 0.4572)
		(drill 0.2032)
		(layers "F.Cu" "B.Cu")
		(net "GND")
	)
	(via
		(at 49.04105 -403.249892)
		(size 0.4572)
		(drill 0.254)
		(layers "F.Cu" "B.Cu")
		(net "GND")
	)
	(via
		(at 87.205312 -237.411768)
		(size 0.4572)
		(drill 0.2032)
		(layers "F.Cu" "B.Cu")
		(net "GND")
	)
	(via
		(at 285.150814 -300.166786)
		(size 0.4572)
		(drill 0.2032)
		(layers "F.Cu" "B.Cu")
		(net "GND")
	)
	(via
		(at 11.135614 -297.616626)
		(size 0.4572)
		(drill 0.2032)
		(layers "F.Cu" "B.Cu")
		(net "GND")
	)
	(via
		(at 112.399572 -419.04158)
		(size 0.508)
		(drill 0.254)
		(layers "F.Cu" "B.Cu")
		(net "GND")
	)
	(via
		(at 460.664814 -270.416782)
		(size 0.4572)
		(drill 0.2032)
		(layers "F.Cu" "B.Cu")
		(net "GND")
	)
	(via
		(at 285.150814 -227.066602)
		(size 0.4572)
		(drill 0.2032)
		(layers "F.Cu" "B.Cu")
		(net "GND")
	)
	(via
		(at 342.924892 -332.56601)
		(size 0.49022)
		(drill 0.254)
		(layers "F.Cu" "B.Cu")
		(net "GND")
	)
	(via
		(at 101.302312 -248.806208)
		(size 0.4572)
		(drill 0.2032)
		(layers "F.Cu" "B.Cu")
		(net "GND")
	)
	(via
		(at 224.401888 -97.25914)
		(size 0.508)
		(drill 0.254)
		(layers "F.Cu" "B.Cu")
		(net "GND")
	)
	(via
		(at 199.527414 -222.816674)
		(size 0.4572)
		(drill 0.2032)
		(layers "F.Cu" "B.Cu")
		(net "GND")
	)
	(via
		(at 410.35732 -182.395368)
		(size 0.508)
		(drill 0.254)
		(layers "F.Cu" "B.Cu")
		(net "GND")
	)
	(via
		(at 420.736014 -300.166786)
		(size 0.4572)
		(drill 0.2032)
		(layers "F.Cu" "B.Cu")
		(net "GND")
	)
	(via
		(at 82.250026 -436.051198)
		(size 0.4572)
		(drill 0.2032)
		(layers "F.Cu" "B.Cu")
		(net "GND")
	)
	(via
		(at 257.185414 -251.716794)
		(size 0.4572)
		(drill 0.2032)
		(layers "F.Cu" "B.Cu")
		(net "GND")
	)
	(via
		(at 42.300652 -4.962652)
		(size 0.508)
		(drill 0.254)
		(layers "F.Cu" "B.Cu")
		(net "GND")
	)
	(via
		(at 337.478116 -400.224244)
		(size 0.4572)
		(drill 0.254)
		(layers "F.Cu" "B.Cu")
		(net "GND")
	)
	(via
		(at 198.276718 -75.27163)
		(size 0.508)
		(drill 0.254)
		(layers "F.Cu" "B.Cu")
		(net "GND")
	)
	(via
		(at 324.753478 -69.198744)
		(size 0.508)
		(drill 0.254)
		(layers "F.Cu" "B.Cu")
		(net "GND")
	)
	(via
		(at 202.971146 -242.3668)
		(size 0.4572)
		(drill 0.2032)
		(layers "F.Cu" "B.Cu")
		(net "GND")
	)
	(via
		(at 128.785874 -403.883876)
		(size 0.4064)
		(drill 0.2032)
		(layers "F.Cu" "B.Cu")
		(net "GND")
	)
	(via
		(at 112.110266 -226.831144)
		(size 0.4572)
		(drill 0.2032)
		(layers "F.Cu" "B.Cu")
		(net "GND")
	)
	(via
		(at 176.896014 -250.866656)
		(size 0.4572)
		(drill 0.2032)
		(layers "F.Cu" "B.Cu")
		(net "GND")
	)
	(via
		(at 291.460682 -249.166634)
		(size 0.4572)
		(drill 0.2032)
		(layers "F.Cu" "B.Cu")
		(net "GND")
	)
	(via
		(at 442.133482 -308.666642)
		(size 0.4572)
		(drill 0.2032)
		(layers "F.Cu" "B.Cu")
		(net "GND")
	)
	(via
		(at 270.837152 -323.429376)
		(size 0.4572)
		(drill 0.2032)
		(layers "F.Cu" "B.Cu")
		(net "GND")
	)
	(via
		(at 378.84608 -246.364506)
		(size 0.4572)
		(drill 0.2032)
		(layers "F.Cu" "B.Cu")
		(net "GND")
	)
	(via
		(at 336.899758 -59.889136)
		(size 0.4572)
		(drill 0.2032)
		(layers "F.Cu" "B.Cu")
		(net "GND")
	)
	(via
		(at 332.5114 -60.065158)
		(size 0.4572)
		(drill 0.2032)
		(layers "F.Cu" "B.Cu")
		(net "GND")
	)
	(via
		(at 18.679414 -282.316682)
		(size 0.4572)
		(drill 0.2032)
		(layers "F.Cu" "B.Cu")
		(net "GND")
	)
	(via
		(at 442.133482 -239.81664)
		(size 0.4572)
		(drill 0.2032)
		(layers "F.Cu" "B.Cu")
		(net "GND")
	)
	(via
		(at 63.726314 -312.91657)
		(size 0.4572)
		(drill 0.2032)
		(layers "F.Cu" "B.Cu")
		(net "GND")
	)
	(via
		(at 39.420546 -208.366614)
		(size 0.4572)
		(drill 0.2032)
		(layers "F.Cu" "B.Cu")
		(net "GND")
	)
	(via
		(at 460.3115 -386.54482)
		(size 0.508)
		(drill 0.254)
		(layers "F.Cu" "B.Cu")
		(net "GND")
	)
	(via
		(at 106.86034 -61.590428)
		(size 0.508)
		(drill 0.254)
		(layers "F.Cu" "B.Cu")
		(net "GND")
	)
	(via
		(at 13.345414 -198.166736)
		(size 0.4572)
		(drill 0.2032)
		(layers "F.Cu" "B.Cu")
		(net "GND")
	)
	(via
		(at 368.148616 -275.08073)
		(size 0.4572)
		(drill 0.2032)
		(layers "F.Cu" "B.Cu")
		(net "GND")
	)
	(via
		(at 41.310814 -230.466646)
		(size 0.4572)
		(drill 0.2032)
		(layers "F.Cu" "B.Cu")
		(net "GND")
	)
	(via
		(at 393.65301 -410.030168)
		(size 0.4064)
		(drill 0.2032)
		(layers "F.Cu" "B.Cu")
		(net "GND")
	)
	(via
		(at 190.093346 -311.216802)
		(size 0.4572)
		(drill 0.2032)
		(layers "F.Cu" "B.Cu")
		(net "GND")
	)
	(via
		(at 54.508146 -229.616762)
		(size 0.4572)
		(drill 0.2032)
		(layers "F.Cu" "B.Cu")
		(net "GND")
	)
	(via
		(at 409.69692 -173.759368)
		(size 0.508)
		(drill 0.254)
		(layers "F.Cu" "B.Cu")
		(net "GND")
	)
	(via
		(at 50.748438 -410.030168)
		(size 0.4064)
		(drill 0.2032)
		(layers "F.Cu" "B.Cu")
		(net "GND")
	)
	(via
		(at 59.842146 -210.916774)
		(size 0.4572)
		(drill 0.2032)
		(layers "F.Cu" "B.Cu")
		(net "GND")
	)
	(via
		(at 159.42183 -60.162948)
		(size 0.508)
		(drill 0.254)
		(layers "F.Cu" "B.Cu")
		(net "GND")
	)
	(via
		(at 167.461946 -258.516628)
		(size 0.4572)
		(drill 0.2032)
		(layers "F.Cu" "B.Cu")
		(net "GND")
	)
	(via
		(at 59.626246 -285.716726)
		(size 0.4572)
		(drill 0.2032)
		(layers "F.Cu" "B.Cu")
		(net "GND")
	)
	(via
		(at 347.805248 -329.119738)
		(size 0.508)
		(drill 0.254)
		(layers "F.Cu" "B.Cu")
		(net "GND")
	)
	(via
		(at 76.934314 -36.019994)
		(size 0.508)
		(drill 0.254)
		(layers "F.Cu" "B.Cu")
		(net "GND")
	)
	(via
		(at 291.681916 -56.559958)
		(size 0.508)
		(drill 0.254)
		(layers "F.Cu" "B.Cu")
		(net "GND")
	)
	(via
		(at 347.473016 -265.314176)
		(size 0.4572)
		(drill 0.2032)
		(layers "F.Cu" "B.Cu")
		(net "GND")
	)
	(via
		(at 195.427346 -201.56678)
		(size 0.4572)
		(drill 0.2032)
		(layers "F.Cu" "B.Cu")
		(net "GND")
	)
	(via
		(at 120.208548 -283.219906)
		(size 0.4572)
		(drill 0.2032)
		(layers "F.Cu" "B.Cu")
		(net "GND")
	)
	(via
		(at 95.193866 -220.319854)
		(size 0.4572)
		(drill 0.2032)
		(layers "F.Cu" "B.Cu")
		(net "GND")
	)
	(via
		(at 372.484142 -403.249892)
		(size 0.4572)
		(drill 0.254)
		(layers "F.Cu" "B.Cu")
		(net "GND")
	)
	(via
		(at 18.679414 -200.716642)
		(size 0.4572)
		(drill 0.2032)
		(layers "F.Cu" "B.Cu")
		(net "GND")
	)
	(via
		(at 438.033414 -208.366614)
		(size 0.4572)
		(drill 0.2032)
		(layers "F.Cu" "B.Cu")
		(net "GND")
	)
	(via
		(at 374.257062 -287.28924)
		(size 0.4572)
		(drill 0.2032)
		(layers "F.Cu" "B.Cu")
		(net "GND")
	)
	(via
		(at 53.682392 -176.171098)
		(size 0.508)
		(drill 0.254)
		(layers "F.Cu" "B.Cu")
		(net "GND")
	)
	(via
		(at 390.844278 -345.65717)
		(size 0.508)
		(drill 0.254)
		(layers "F.Cu" "B.Cu")
		(net "GND")
	)
	(via
		(at 298.19346 -152.956768)
		(size 0.508)
		(drill 0.254)
		(layers "F.Cu" "B.Cu")
		(net "GND")
	)
	(via
		(at 294.904414 -217.716608)
		(size 0.4572)
		(drill 0.2032)
		(layers "F.Cu" "B.Cu")
		(net "GND")
	)
	(via
		(at 51.221894 -351.608644)
		(size 0.49022)
		(drill 0.254)
		(layers "F.Cu" "B.Cu")
		(net "GND")
	)
	(via
		(at 175.005746 -300.166786)
		(size 0.4572)
		(drill 0.2032)
		(layers "F.Cu" "B.Cu")
		(net "GND")
	)
	(via
		(at 190.093346 -317.166752)
		(size 0.4572)
		(drill 0.2032)
		(layers "F.Cu" "B.Cu")
		(net "GND")
	)
	(via
		(at 167.461946 -298.466764)
		(size 0.4572)
		(drill 0.2032)
		(layers "F.Cu" "B.Cu")
		(net "GND")
	)
	(via
		(at 215.0618 -120.142)
		(size 0.508)
		(drill 0.254)
		(layers "F.Cu" "B.Cu")
		(net "GND")
	)
	(via
		(at 349.556832 -331.703426)
		(size 0.508)
		(drill 0.254)
		(layers "F.Cu" "B.Cu")
		(net "GND")
	)
	(via
		(at 339.484716 -264.50036)
		(size 0.4572)
		(drill 0.2032)
		(layers "F.Cu" "B.Cu")
		(net "GND")
	)
	(via
		(at 161.808414 -299.316648)
		(size 0.4572)
		(drill 0.2032)
		(layers "F.Cu" "B.Cu")
		(net "GND")
	)
	(via
		(at 46.964346 -201.56678)
		(size 0.4572)
		(drill 0.2032)
		(layers "F.Cu" "B.Cu")
		(net "GND")
	)
	(via
		(at 380.0348 -91.318588)
		(size 0.508)
		(drill 0.254)
		(layers "F.Cu" "B.Cu")
		(net "GND")
	)
	(via
		(at 413.349948 -428.851314)
		(size 0.4572)
		(drill 0.2032)
		(layers "F.Cu" "B.Cu")
		(net "GND")
	)
	(via
		(at 58.608214 -226.216718)
		(size 0.4572)
		(drill 0.2032)
		(layers "F.Cu" "B.Cu")
		(net "GND")
	)
	(via
		(at 44.754546 -199.01662)
		(size 0.4572)
		(drill 0.2032)
		(layers "F.Cu" "B.Cu")
		(net "GND")
	)
	(via
		(at 51.064414 -295.916604)
		(size 0.4572)
		(drill 0.2032)
		(layers "F.Cu" "B.Cu")
		(net "GND")
	)
	(via
		(at 80.25003 -427.851316)
		(size 0.4572)
		(drill 0.2032)
		(layers "F.Cu" "B.Cu")
		(net "GND")
	)
	(via
		(at 360.736388 -46.802802)
		(size 0.508)
		(drill 0.254)
		(layers "F.Cu" "B.Cu")
		(net "GND")
	)
	(via
		(at 58.608214 -247.466612)
		(size 0.4572)
		(drill 0.2032)
		(layers "F.Cu" "B.Cu")
		(net "GND")
	)
	(via
		(at 373.317262 -267.755878)
		(size 0.4572)
		(drill 0.2032)
		(layers "F.Cu" "B.Cu")
		(net "GND")
	)
	(via
		(at 33.767014 -262.76681)
		(size 0.4572)
		(drill 0.2032)
		(layers "F.Cu" "B.Cu")
		(net "GND")
	)
	(via
		(at 210.514946 -206.666592)
		(size 0.4572)
		(drill 0.2032)
		(layers "F.Cu" "B.Cu")
		(net "GND")
	)
	(via
		(at 18.679414 -250.866656)
		(size 0.4572)
		(drill 0.2032)
		(layers "F.Cu" "B.Cu")
		(net "GND")
	)
	(via
		(at 209.281014 -278.916638)
		(size 0.4572)
		(drill 0.2032)
		(layers "F.Cu" "B.Cu")
		(net "GND")
	)
	(via
		(at 430.489614 -295.06672)
		(size 0.4572)
		(drill 0.2032)
		(layers "F.Cu" "B.Cu")
		(net "GND")
	)
	(via
		(at 180.339746 -210.916774)
		(size 0.4572)
		(drill 0.2032)
		(layers "F.Cu" "B.Cu")
		(net "GND")
	)
	(via
		(at 443.367414 -229.616762)
		(size 0.4572)
		(drill 0.2032)
		(layers "F.Cu" "B.Cu")
		(net "GND")
	)
	(via
		(at 307.782214 -296.766742)
		(size 0.4572)
		(drill 0.2032)
		(layers "F.Cu" "B.Cu")
		(net "GND")
	)
	(via
		(at 386.474462 -267.755878)
		(size 0.4572)
		(drill 0.2032)
		(layers "F.Cu" "B.Cu")
		(net "GND")
	)
	(via
		(at 289.250882 -213.46668)
		(size 0.4572)
		(drill 0.2032)
		(layers "F.Cu" "B.Cu")
		(net "GND")
	)
	(via
		(at 299.004482 -210.066636)
		(size 0.4572)
		(drill 0.2032)
		(layers "F.Cu" "B.Cu")
		(net "GND")
	)
	(via
		(at 419.502082 -314.616592)
		(size 0.4572)
		(drill 0.2032)
		(layers "F.Cu" "B.Cu")
		(net "GND")
	)
	(via
		(at 191.983614 -299.316648)
		(size 0.4572)
		(drill 0.2032)
		(layers "F.Cu" "B.Cu")
		(net "GND")
	)
	(via
		(at 37.210746 -221.96679)
		(size 0.4572)
		(drill 0.2032)
		(layers "F.Cu" "B.Cu")
		(net "GND")
	)
	(via
		(at 87.507318 -410.030168)
		(size 0.4064)
		(drill 0.2032)
		(layers "F.Cu" "B.Cu")
		(net "GND")
	)
	(via
		(at 423.19194 -382.184148)
		(size 0.508)
		(drill 0.254)
		(layers "F.Cu" "B.Cu")
		(net "GND")
	)
	(via
		(at 294.904414 -270.416782)
		(size 0.4572)
		(drill 0.2032)
		(layers "F.Cu" "B.Cu")
		(net "GND")
	)
	(via
		(at 195.427346 -272.116804)
		(size 0.4572)
		(drill 0.2032)
		(layers "F.Cu" "B.Cu")
		(net "GND")
	)
	(via
		(at 33.767014 -226.216718)
		(size 0.4572)
		(drill 0.2032)
		(layers "F.Cu" "B.Cu")
		(net "GND")
	)
	(via
		(at 325.250048 -431.29962)
		(size 0.4572)
		(drill 0.2032)
		(layers "F.Cu" "B.Cu")
		(net "GND")
	)
	(via
		(at 239.99952 -53.583586)
		(size 0.508)
		(drill 0.254)
		(layers "F.Cu" "B.Cu")
		(net "GND")
	)
	(via
		(at 294.904414 -260.21665)
		(size 0.4572)
		(drill 0.2032)
		(layers "F.Cu" "B.Cu")
		(net "GND")
	)
	(via
		(at 39.420546 -212.616796)
		(size 0.4572)
		(drill 0.2032)
		(layers "F.Cu" "B.Cu")
		(net "GND")
	)
	(via
		(at 405.648414 -306.116736)
		(size 0.4572)
		(drill 0.2032)
		(layers "F.Cu" "B.Cu")
		(net "GND")
	)
	(via
		(at 18.679414 -264.466578)
		(size 0.4572)
		(drill 0.2032)
		(layers "F.Cu" "B.Cu")
		(net "GND")
	)
	(via
		(at 164.018214 -226.216718)
		(size 0.4572)
		(drill 0.2032)
		(layers "F.Cu" "B.Cu")
		(net "GND")
	)
	(via
		(at 131.015994 -267.755878)
		(size 0.4572)
		(drill 0.2032)
		(layers "F.Cu" "B.Cu")
		(net "GND")
	)
	(via
		(at 464.764882 -289.966654)
		(size 0.4572)
		(drill 0.2032)
		(layers "F.Cu" "B.Cu")
		(net "GND")
	)
	(via
		(at 418.356796 -12.37488)
		(size 0.508)
		(drill 0.254)
		(layers "F.Cu" "B.Cu")
		(net "GND")
	)
	(via
		(at 419.9001 -4.317746)
		(size 0.508)
		(drill 0.254)
		(layers "F.Cu" "B.Cu")
		(net "GND")
	)
	(via
		(at 80.035654 -342.556084)
		(size 0.49022)
		(drill 0.254)
		(layers "F.Cu" "B.Cu")
		(net "GND")
	)
	(via
		(at 287.360614 -233.016806)
		(size 0.4572)
		(drill 0.2032)
		(layers "F.Cu" "B.Cu")
		(net "GND")
	)
	(via
		(at 314.092082 -222.816674)
		(size 0.4572)
		(drill 0.2032)
		(layers "F.Cu" "B.Cu")
		(net "GND")
	)
	(via
		(at 129.026412 -228.45903)
		(size 0.4572)
		(drill 0.2032)
		(layers "F.Cu" "B.Cu")
		(net "GND")
	)
	(via
		(at 325.250048 -434.899562)
		(size 0.4572)
		(drill 0.2032)
		(layers "F.Cu" "B.Cu")
		(net "GND")
	)
	(via
		(at 210.594956 -38.169342)
		(size 0.508)
		(drill 0.254)
		(layers "F.Cu" "B.Cu")
		(net "GND")
	)
	(via
		(at 159.918146 -225.36658)
		(size 0.4572)
		(drill 0.2032)
		(layers "F.Cu" "B.Cu")
		(net "GND")
	)
	(via
		(at 164.262562 -238.116618)
		(size 0.4572)
		(drill 0.2032)
		(layers "F.Cu" "B.Cu")
		(net "GND")
	)
	(via
		(at 377.076462 -261.244842)
		(size 0.4572)
		(drill 0.2032)
		(layers "F.Cu" "B.Cu")
		(net "GND")
	)
	(via
		(at 417.292282 -286.56661)
		(size 0.4572)
		(drill 0.2032)
		(layers "F.Cu" "B.Cu")
		(net "GND")
	)
	(via
		(at 291.460682 -210.066636)
		(size 0.4572)
		(drill 0.2032)
		(layers "F.Cu" "B.Cu")
		(net "GND")
	)
	(via
		(at 371.35054 -164.043868)
		(size 0.508)
		(drill 0.254)
		(layers "F.Cu" "B.Cu")
		(net "GND")
	)
	(via
		(at 435.823614 -313.766708)
		(size 0.4572)
		(drill 0.2032)
		(layers "F.Cu" "B.Cu")
		(net "GND")
	)
	(via
		(at 430.81448 -128.761998)
		(size 0.508)
		(drill 0.254)
		(layers "F.Cu" "B.Cu")
		(net "GND")
	)
	(via
		(at 387.493256 -270.4719)
		(size 0.4572)
		(drill 0.2032)
		(layers "F.Cu" "B.Cu")
		(net "GND")
	)
	(via
		(at 340.08314 -410.664152)
		(size 0.4572)
		(drill 0.254)
		(layers "F.Cu" "B.Cu")
		(net "GND")
	)
	(via
		(at 442.133482 -303.566576)
		(size 0.4572)
		(drill 0.2032)
		(layers "F.Cu" "B.Cu")
		(net "GND")
	)
	(via
		(at 254.975614 -208.366614)
		(size 0.4572)
		(drill 0.2032)
		(layers "F.Cu" "B.Cu")
		(net "GND")
	)
	(via
		(at 420.736014 -225.36658)
		(size 0.4572)
		(drill 0.2032)
		(layers "F.Cu" "B.Cu")
		(net "GND")
	)
	(via
		(at 289.405568 -411.696154)
		(size 0.508)
		(drill 0.254)
		(layers "F.Cu" "B.Cu")
		(net "GND")
	)
	(via
		(at 304.338482 -230.466646)
		(size 0.4572)
		(drill 0.2032)
		(layers "F.Cu" "B.Cu")
		(net "GND")
	)
	(via
		(at 337.495388 -223.575626)
		(size 0.4572)
		(drill 0.2032)
		(layers "F.Cu" "B.Cu")
		(net "GND")
	)
	(via
		(at 156.12364 -187.846462)
		(size 0.508)
		(drill 0.254)
		(layers "F.Cu" "B.Cu")
		(net "GND")
	)
	(via
		(at 7.035546 -206.666592)
		(size 0.4572)
		(drill 0.2032)
		(layers "F.Cu" "B.Cu")
		(net "GND")
	)
	(via
		(at 186.649614 -247.466612)
		(size 0.4572)
		(drill 0.2032)
		(layers "F.Cu" "B.Cu")
		(net "GND")
	)
	(via
		(at 330.252578 -47.040546)
		(size 0.4572)
		(drill 0.2032)
		(layers "F.Cu" "B.Cu")
		(net "GND")
	)
	(via
		(at 128.569974 -356.83952)
		(size 0.508)
		(drill 0.254)
		(layers "F.Cu" "B.Cu")
		(net "GND")
	)
	(via
		(at 76.644754 -32.376364)
		(size 0.508)
		(drill 0.254)
		(layers "F.Cu" "B.Cu")
		(net "GND")
	)
	(via
		(at 44.754546 -278.066754)
		(size 0.4572)
		(drill 0.2032)
		(layers "F.Cu" "B.Cu")
		(net "GND")
	)
	(via
		(at 381.195834 -219.506038)
		(size 0.4572)
		(drill 0.2032)
		(layers "F.Cu" "B.Cu")
		(net "GND")
	)
	(via
		(at 199.41413 -12.544552)
		(size 0.508)
		(drill 0.254)
		(layers "F.Cu" "B.Cu")
		(net "GND")
	)
	(via
		(at 261.285482 -291.666676)
		(size 0.4572)
		(drill 0.2032)
		(layers "F.Cu" "B.Cu")
		(net "GND")
	)
	(via
		(at 379.786134 -234.970066)
		(size 0.4572)
		(drill 0.2032)
		(layers "F.Cu" "B.Cu")
		(net "GND")
	)
	(via
		(at 432.379882 -207.51673)
		(size 0.4572)
		(drill 0.2032)
		(layers "F.Cu" "B.Cu")
		(net "GND")
	)
	(via
		(at 166.846758 -130.737864)
		(size 0.508)
		(drill 0.254)
		(layers "F.Cu" "B.Cu")
		(net "GND")
	)
	(via
		(at 26.223214 -196.466714)
		(size 0.4572)
		(drill 0.2032)
		(layers "F.Cu" "B.Cu")
		(net "GND")
	)
	(via
		(at 355.96576 -329.76312)
		(size 0.508)
		(drill 0.254)
		(layers "F.Cu" "B.Cu")
		(net "GND")
	)
	(via
		(at 86.265766 -222.761556)
		(size 0.4572)
		(drill 0.2032)
		(layers "F.Cu" "B.Cu")
		(net "GND")
	)
	(via
		(at 304.29454 -366.243108)
		(size 0.49022)
		(drill 0.254)
		(layers "F.Cu" "B.Cu")
		(net "GND")
	)
	(via
		(at 187.883546 -290.816792)
		(size 0.4572)
		(drill 0.2032)
		(layers "F.Cu" "B.Cu")
		(net "GND")
	)
	(via
		(at 126.350014 -432.747166)
		(size 0.4572)
		(drill 0.2032)
		(layers "F.Cu" "B.Cu")
		(net "GND")
	)
	(via
		(at 205.180946 -201.56678)
		(size 0.4572)
		(drill 0.2032)
		(layers "F.Cu" "B.Cu")
		(net "GND")
	)
	(via
		(at 182.549546 -261.916672)
		(size 0.4572)
		(drill 0.2032)
		(layers "F.Cu" "B.Cu")
		(net "GND")
	)
	(via
		(at 87.675466 -231.714548)
		(size 0.4572)
		(drill 0.2032)
		(layers "F.Cu" "B.Cu")
		(net "GND")
	)
	(via
		(at 117.075458 -331.87132)
		(size 0.508)
		(drill 0.254)
		(layers "F.Cu" "B.Cu")
		(net "GND")
	)
	(via
		(at 450.56298 -111.308388)
		(size 0.508)
		(drill 0.254)
		(layers "F.Cu" "B.Cu")
		(net "GND")
	)
	(via
		(at 60.334906 -44.263564)
		(size 0.508)
		(drill 0.254)
		(layers "F.Cu" "B.Cu")
		(net "GND")
	)
	(via
		(at 54.724046 -220.266768)
		(size 0.4572)
		(drill 0.2032)
		(layers "F.Cu" "B.Cu")
		(net "GND")
	)
	(via
		(at 274.163282 -288.266632)
		(size 0.4572)
		(drill 0.2032)
		(layers "F.Cu" "B.Cu")
		(net "GND")
	)
	(via
		(at 382.35001 -430.299622)
		(size 0.4572)
		(drill 0.2032)
		(layers "F.Cu" "B.Cu")
		(net "GND")
	)
	(via
		(at 216.824814 -288.266632)
		(size 0.4572)
		(drill 0.2032)
		(layers "F.Cu" "B.Cu")
		(net "GND")
	)
	(via
		(at 117.749066 -223.575626)
		(size 0.4572)
		(drill 0.2032)
		(layers "F.Cu" "B.Cu")
		(net "GND")
	)
	(via
		(at 100.362766 -237.411514)
		(size 0.4572)
		(drill 0.2032)
		(layers "F.Cu" "B.Cu")
		(net "GND")
	)
	(via
		(at 179.105814 -204.116686)
		(size 0.4572)
		(drill 0.2032)
		(layers "F.Cu" "B.Cu")
		(net "GND")
	)
	(via
		(at 296.794682 -232.166668)
		(size 0.4572)
		(drill 0.2032)
		(layers "F.Cu" "B.Cu")
		(net "GND")
	)
	(via
		(at 16.789146 -244.916706)
		(size 0.4572)
		(drill 0.2032)
		(layers "F.Cu" "B.Cu")
		(net "GND")
	)
	(via
		(at 382.715262 -257.98907)
		(size 0.4572)
		(drill 0.2032)
		(layers "F.Cu" "B.Cu")
		(net "GND")
	)
	(via
		(at 226.903534 -121.994422)
		(size 0.508)
		(drill 0.254)
		(layers "F.Cu" "B.Cu")
		(net "GND")
	)
	(via
		(at 288.479992 -387.143498)
		(size 0.508)
		(drill 0.254)
		(layers "F.Cu" "B.Cu")
		(net "GND")
	)
	(via
		(at 26.223214 -244.066568)
		(size 0.4572)
		(drill 0.2032)
		(layers "F.Cu" "B.Cu")
		(net "GND")
	)
	(via
		(at 289.250882 -316.316614)
		(size 0.4572)
		(drill 0.2032)
		(layers "F.Cu" "B.Cu")
		(net "GND")
	)
	(via
		(at 283.916882 -235.566712)
		(size 0.4572)
		(drill 0.2032)
		(layers "F.Cu" "B.Cu")
		(net "GND")
	)
	(via
		(at 372.67642 -64.127888)
		(size 0.508)
		(drill 0.254)
		(layers "F.Cu" "B.Cu")
		(net "GND")
	)
	(via
		(at 445.577214 -273.816572)
		(size 0.4572)
		(drill 0.2032)
		(layers "F.Cu" "B.Cu")
		(net "GND")
	)
	(via
		(at 102.821994 -269.38351)
		(size 0.4572)
		(drill 0.2032)
		(layers "F.Cu" "B.Cu")
		(net "GND")
	)
	(via
		(at 450.911214 -301.866808)
		(size 0.4572)
		(drill 0.2032)
		(layers "F.Cu" "B.Cu")
		(net "GND")
	)
	(via
		(at 122.917712 -239.0394)
		(size 0.4572)
		(drill 0.2032)
		(layers "F.Cu" "B.Cu")
		(net "GND")
	)
	(via
		(at 59.250072 -437.49976)
		(size 0.4572)
		(drill 0.2032)
		(layers "F.Cu" "B.Cu")
		(net "GND")
	)
	(via
		(at 172.795946 -307.816758)
		(size 0.4572)
		(drill 0.2032)
		(layers "F.Cu" "B.Cu")
		(net "GND")
	)
	(via
		(at 170.671998 -351.614994)
		(size 0.49022)
		(drill 0.254)
		(layers "F.Cu" "B.Cu")
		(net "GND")
	)
	(via
		(at 153.34996 -431.29962)
		(size 0.4572)
		(drill 0.2032)
		(layers "F.Cu" "B.Cu")
		(net "GND")
	)
	(via
		(at 121.508266 -220.319854)
		(size 0.4572)
		(drill 0.2032)
		(layers "F.Cu" "B.Cu")
		(net "GND")
	)
	(via
		(at 14.828266 -17.61236)
		(size 0.508)
		(drill 0.254)
		(layers "F.Cu" "B.Cu")
		(net "GND")
	)
	(via
		(at 332.144624 -337.643216)
		(size 0.508)
		(drill 0.254)
		(layers "F.Cu" "B.Cu")
		(net "GND")
	)
	(via
		(at 272.273014 -281.466798)
		(size 0.4572)
		(drill 0.2032)
		(layers "F.Cu" "B.Cu")
		(net "GND")
	)
	(via
		(at 144.54632 -105.156508)
		(size 0.508)
		(drill 0.254)
		(layers "F.Cu" "B.Cu")
		(net "GND")
	)
	(via
		(at 287.493964 -441.225432)
		(size 0.508)
		(drill 0.254)
		(layers "F.Cu" "B.Cu")
		(net "GND")
	)
	(via
		(at 287.360614 -279.766776)
		(size 0.4572)
		(drill 0.2032)
		(layers "F.Cu" "B.Cu")
		(net "GND")
	)
	(via
		(at 25.946608 -129.380996)
		(size 0.508)
		(drill 0.254)
		(layers "F.Cu" "B.Cu")
		(net "GND")
	)
	(via
		(at 23.946866 -10.16508)
		(size 0.508)
		(drill 0.254)
		(layers "F.Cu" "B.Cu")
		(net "GND")
	)
	(via
		(at 296.774108 -163.102544)
		(size 0.508)
		(drill 0.254)
		(layers "F.Cu" "B.Cu")
		(net "GND")
	)
	(via
		(at 20.346924 -12.37488)
		(size 0.508)
		(drill 0.254)
		(layers "F.Cu" "B.Cu")
		(net "GND")
	)
	(via
		(at 87.315294 -271.825212)
		(size 0.4318)
		(drill 0.2032)
		(layers "F.Cu" "B.Cu")
		(net "GND")
	)
	(via
		(at 358.295702 -297.197526)
		(size 0.508)
		(drill 0.254)
		(layers "F.Cu" "B.Cu")
		(net "GND")
	)
	(via
		(at 340.006686 -12.544552)
		(size 0.508)
		(drill 0.254)
		(layers "F.Cu" "B.Cu")
		(net "GND")
	)
	(via
		(at 217.637868 -104.33304)
		(size 0.508)
		(drill 0.254)
		(layers "F.Cu" "B.Cu")
		(net "GND")
	)
	(via
		(at 100.362766 -247.178322)
		(size 0.4572)
		(drill 0.2032)
		(layers "F.Cu" "B.Cu")
		(net "GND")
	)
	(via
		(at 131.752086 -410.664152)
		(size 0.4572)
		(drill 0.254)
		(layers "F.Cu" "B.Cu")
		(net "GND")
	)
	(via
		(at 26.223214 -267.866622)
		(size 0.4572)
		(drill 0.2032)
		(layers "F.Cu" "B.Cu")
		(net "GND")
	)
	(via
		(at 368.392964 -326.948292)
		(size 0.508)
		(drill 0.254)
		(layers "F.Cu" "B.Cu")
		(net "GND")
	)
	(via
		(at 194.193414 -221.116652)
		(size 0.4572)
		(drill 0.2032)
		(layers "F.Cu" "B.Cu")
		(net "GND")
	)
	(via
		(at 414.070292 -163.538154)
		(size 0.49022)
		(drill 0.254)
		(layers "F.Cu" "B.Cu")
		(net "GND")
	)
	(via
		(at 141.400022 -400.224244)
		(size 0.4572)
		(drill 0.254)
		(layers "F.Cu" "B.Cu")
		(net "GND")
	)
	(via
		(at 348.302834 -232.528364)
		(size 0.4572)
		(drill 0.2032)
		(layers "F.Cu" "B.Cu")
		(net "GND")
	)
	(via
		(at 205.180946 -231.316784)
		(size 0.4572)
		(drill 0.2032)
		(layers "F.Cu" "B.Cu")
		(net "GND")
	)
	(via
		(at 314.092082 -249.166634)
		(size 0.4572)
		(drill 0.2032)
		(layers "F.Cu" "B.Cu")
		(net "GND")
	)
	(via
		(at 18.753328 -429.097948)
		(size 0.508)
		(drill 0.254)
		(layers "F.Cu" "B.Cu")
		(net "GND")
	)
	(via
		(at 31.876746 -311.216802)
		(size 0.4572)
		(drill 0.2032)
		(layers "F.Cu" "B.Cu")
		(net "GND")
	)
	(via
		(at 62.051946 -233.016806)
		(size 0.4572)
		(drill 0.2032)
		(layers "F.Cu" "B.Cu")
		(net "GND")
	)
	(via
		(at 455.011282 -216.866724)
		(size 0.4572)
		(drill 0.2032)
		(layers "F.Cu" "B.Cu")
		(net "GND")
	)
	(via
		(at 368.916204 -245.01475)
		(size 0.4572)
		(drill 0.2032)
		(layers "F.Cu" "B.Cu")
		(net "GND")
	)
	(via
		(at 323.42074 -403.249892)
		(size 0.4572)
		(drill 0.254)
		(layers "F.Cu" "B.Cu")
		(net "GND")
	)
	(via
		(at 432.379882 -219.41663)
		(size 0.4572)
		(drill 0.2032)
		(layers "F.Cu" "B.Cu")
		(net "GND")
	)
	(via
		(at 458.455014 -201.56678)
		(size 0.4572)
		(drill 0.2032)
		(layers "F.Cu" "B.Cu")
		(net "GND")
	)
	(via
		(at 360.050334 -220.319854)
		(size 0.4572)
		(drill 0.2032)
		(layers "F.Cu" "B.Cu")
		(net "GND")
	)
	(via
		(at 386.474462 -271.011396)
		(size 0.4572)
		(drill 0.2032)
		(layers "F.Cu" "B.Cu")
		(net "GND")
	)
	(via
		(at 358.890316 -35.240468)
		(size 0.508)
		(drill 0.254)
		(layers "F.Cu" "B.Cu")
		(net "GND")
	)
	(via
		(at 369.088416 -276.708616)
		(size 0.4572)
		(drill 0.2032)
		(layers "F.Cu" "B.Cu")
		(net "GND")
	)
	(via
		(at 303.421288 -400.858228)
		(size 0.4064)
		(drill 0.2032)
		(layers "F.Cu" "B.Cu")
		(net "GND")
	)
	(via
		(at 438.033414 -216.016586)
		(size 0.4572)
		(drill 0.2032)
		(layers "F.Cu" "B.Cu")
		(net "GND")
	)
	(via
		(at 130.906012 -236.597952)
		(size 0.4572)
		(drill 0.2032)
		(layers "F.Cu" "B.Cu")
		(net "GND")
	)
	(via
		(at 320.3575 -404.51786)
		(size 0.4572)
		(drill 0.254)
		(layers "F.Cu" "B.Cu")
		(net "GND")
	)
	(via
		(at 386.364734 -225.203258)
		(size 0.4572)
		(drill 0.2032)
		(layers "F.Cu" "B.Cu")
		(net "GND")
	)
	(via
		(at 281.707082 -261.066788)
		(size 0.4572)
		(drill 0.2032)
		(layers "F.Cu" "B.Cu")
		(net "GND")
	)
	(via
		(at 303.782476 -400.224244)
		(size 0.4572)
		(drill 0.254)
		(layers "F.Cu" "B.Cu")
		(net "GND")
	)
	(via
		(at 358.170734 -241.481102)
		(size 0.4572)
		(drill 0.2032)
		(layers "F.Cu" "B.Cu")
		(net "GND")
	)
	(via
		(at 352.171762 -286.475424)
		(size 0.4572)
		(drill 0.2032)
		(layers "F.Cu" "B.Cu")
		(net "GND")
	)
	(via
		(at 414.657286 -174.363126)
		(size 0.508)
		(drill 0.254)
		(layers "F.Cu" "B.Cu")
		(net "GND")
	)
	(via
		(at 277.607014 -290.816792)
		(size 0.4572)
		(drill 0.2032)
		(layers "F.Cu" "B.Cu")
		(net "GND")
	)
	(via
		(at 406.179782 -404.51786)
		(size 0.4572)
		(drill 0.254)
		(layers "F.Cu" "B.Cu")
		(net "GND")
	)
	(via
		(at 236.69752 -388.01294)
		(size 0.508)
		(drill 0.254)
		(layers "F.Cu" "B.Cu")
		(net "GND")
	)
	(via
		(at 375.557034 -243.922804)
		(size 0.4572)
		(drill 0.2032)
		(layers "F.Cu" "B.Cu")
		(net "GND")
	)
	(via
		(at 87.205566 -247.178322)
		(size 0.4572)
		(drill 0.2032)
		(layers "F.Cu" "B.Cu")
		(net "GND")
	)
	(via
		(at 104.46639 -332.56601)
		(size 0.49022)
		(drill 0.254)
		(layers "F.Cu" "B.Cu")
		(net "GND")
	)
	(via
		(at 444.775336 -48.495712)
		(size 0.508)
		(drill 0.254)
		(layers "F.Cu" "B.Cu")
		(net "GND")
	)
	(via
		(at 122.917966 -222.761556)
		(size 0.4572)
		(drill 0.2032)
		(layers "F.Cu" "B.Cu")
		(net "GND")
	)
	(via
		(at 363.22 -55.884572)
		(size 0.508)
		(drill 0.254)
		(layers "F.Cu" "B.Cu")
		(net "GND")
	)
	(via
		(at 9.245346 -236.416596)
		(size 0.4572)
		(drill 0.2032)
		(layers "F.Cu" "B.Cu")
		(net "GND")
	)
	(via
		(at 372.299738 -355.95687)
		(size 0.508)
		(drill 0.254)
		(layers "F.Cu" "B.Cu")
		(net "GND")
	)
	(via
		(at 92.365322 -334.494124)
		(size 0.508)
		(drill 0.254)
		(layers "F.Cu" "B.Cu")
		(net "GND")
	)
	(via
		(at 431.22215 -52.10048)
		(size 0.508)
		(drill 0.254)
		(layers "F.Cu" "B.Cu")
		(net "GND")
	)
	(via
		(at 355.461062 -282.405836)
		(size 0.4572)
		(drill 0.2032)
		(layers "F.Cu" "B.Cu")
		(net "GND")
	)
	(via
		(at 279.816814 -223.666558)
		(size 0.4572)
		(drill 0.2032)
		(layers "F.Cu" "B.Cu")
		(net "GND")
	)
	(via
		(at 376.496834 -216.25052)
		(size 0.4572)
		(drill 0.2032)
		(layers "F.Cu" "B.Cu")
		(net "GND")
	)
	(via
		(at 86.845394 -264.50036)
		(size 0.4318)
		(drill 0.2032)
		(layers "F.Cu" "B.Cu")
		(net "GND")
	)
	(via
		(at 92.954348 -278.336502)
		(size 0.4572)
		(drill 0.2032)
		(layers "F.Cu" "B.Cu")
		(net "GND")
	)
	(via
		(at 236.022134 -257.724656)
		(size 0.508)
		(drill 0.254)
		(layers "F.Cu" "B.Cu")
		(net "GND")
	)
	(via
		(at 153.194766 -409.396184)
		(size 0.4572)
		(drill 0.254)
		(layers "F.Cu" "B.Cu")
		(net "GND")
	)
	(via
		(at 394.014198 -410.664152)
		(size 0.4572)
		(drill 0.254)
		(layers "F.Cu" "B.Cu")
		(net "GND")
	)
	(via
		(at 386.541518 -400.224244)
		(size 0.4572)
		(drill 0.254)
		(layers "F.Cu" "B.Cu")
		(net "GND")
	)
	(via
		(at 405.90597 -410.030168)
		(size 0.4064)
		(drill 0.2032)
		(layers "F.Cu" "B.Cu")
		(net "GND")
	)
	(via
		(at 116.919248 -280.778204)
		(size 0.4572)
		(drill 0.2032)
		(layers "F.Cu" "B.Cu")
		(net "GND")
	)
	(via
		(at 48.854614 -306.96662)
		(size 0.4572)
		(drill 0.2032)
		(layers "F.Cu" "B.Cu")
		(net "GND")
	)
	(via
		(at 205.180946 -238.966756)
		(size 0.4572)
		(drill 0.2032)
		(layers "F.Cu" "B.Cu")
		(net "GND")
	)
	(via
		(at 182.43042 -406.494488)
		(size 0.508)
		(drill 0.254)
		(layers "F.Cu" "B.Cu")
		(net "GND")
	)
	(via
		(at 428.279814 -240.666778)
		(size 0.4572)
		(drill 0.2032)
		(layers "F.Cu" "B.Cu")
		(net "GND")
	)
	(via
		(at 84.44611 -60.252356)
		(size 0.508)
		(drill 0.254)
		(layers "F.Cu" "B.Cu")
		(net "GND")
	)
	(via
		(at 62.64021 -407.638504)
		(size 0.4572)
		(drill 0.254)
		(layers "F.Cu" "B.Cu")
		(net "GND")
	)
	(via
		(at 342.250014 -438.499758)
		(size 0.4572)
		(drill 0.2032)
		(layers "F.Cu" "B.Cu")
		(net "GND")
	)
	(via
		(at 197.637146 -311.216802)
		(size 0.4572)
		(drill 0.2032)
		(layers "F.Cu" "B.Cu")
		(net "GND")
	)
	(via
		(at 119.466614 -331.776832)
		(size 0.49022)
		(drill 0.254)
		(layers "F.Cu" "B.Cu")
		(net "GND")
	)
	(via
		(at 385.534662 -280.778204)
		(size 0.4572)
		(drill 0.2032)
		(layers "F.Cu" "B.Cu")
		(net "GND")
	)
	(via
		(at 328.01687 -342.641428)
		(size 0.49022)
		(drill 0.254)
		(layers "F.Cu" "B.Cu")
		(net "GND")
	)
	(via
		(at 410.589222 -406.370536)
		(size 0.4572)
		(drill 0.254)
		(layers "F.Cu" "B.Cu")
		(net "GND")
	)
	(via
		(at 336.250026 -432.747166)
		(size 0.4572)
		(drill 0.2032)
		(layers "F.Cu" "B.Cu")
		(net "GND")
	)
	(via
		(at 397.077438 -409.396184)
		(size 0.4572)
		(drill 0.254)
		(layers "F.Cu" "B.Cu")
		(net "GND")
	)
	(via
		(at 205.180946 -285.716726)
		(size 0.4572)
		(drill 0.2032)
		(layers "F.Cu" "B.Cu")
		(net "GND")
	)
	(via
		(at 52.911248 -155.60167)
		(size 0.49022)
		(drill 0.254)
		(layers "F.Cu" "B.Cu")
		(net "GND")
	)
	(via
		(at 11.135614 -261.066788)
		(size 0.4572)
		(drill 0.2032)
		(layers "F.Cu" "B.Cu")
		(net "GND")
	)
	(via
		(at 457.221082 -202.416664)
		(size 0.4572)
		(drill 0.2032)
		(layers "F.Cu" "B.Cu")
		(net "GND")
	)
	(via
		(at 98.79711 -53.327046)
		(size 0.508)
		(drill 0.254)
		(layers "F.Cu" "B.Cu")
		(net "GND")
	)
	(via
		(at 405.648414 -270.416782)
		(size 0.4572)
		(drill 0.2032)
		(layers "F.Cu" "B.Cu")
		(net "GND")
	)
	(via
		(at 315.250068 -437.49976)
		(size 0.4572)
		(drill 0.2032)
		(layers "F.Cu" "B.Cu")
		(net "GND")
	)
	(via
		(at 428.279814 -212.616796)
		(size 0.4572)
		(drill 0.2032)
		(layers "F.Cu" "B.Cu")
		(net "GND")
	)
	(via
		(at 296.578782 -210.066636)
		(size 0.4572)
		(drill 0.2032)
		(layers "F.Cu" "B.Cu")
		(net "GND")
	)
	(via
		(at 165.252146 -300.166786)
		(size 0.4572)
		(drill 0.2032)
		(layers "F.Cu" "B.Cu")
		(net "GND")
	)
	(via
		(at 411.349952 -437.49976)
		(size 0.4572)
		(drill 0.2032)
		(layers "F.Cu" "B.Cu")
		(net "GND")
	)
	(via
		(at 186.649614 -194.766692)
		(size 0.4572)
		(drill 0.2032)
		(layers "F.Cu" "B.Cu")
		(net "GND")
	)
	(via
		(at 443.367414 -273.816572)
		(size 0.4572)
		(drill 0.2032)
		(layers "F.Cu" "B.Cu")
		(net "GND")
	)
	(via
		(at 16.789146 -317.166752)
		(size 0.4572)
		(drill 0.2032)
		(layers "F.Cu" "B.Cu")
		(net "GND")
	)
	(via
		(at 66.161666 -401.492212)
		(size 0.4572)
		(drill 0.254)
		(layers "F.Cu" "B.Cu")
		(net "GND")
	)
	(via
		(at 92.844366 -230.900478)
		(size 0.4572)
		(drill 0.2032)
		(layers "F.Cu" "B.Cu")
		(net "GND")
	)
	(via
		(at 197.637146 -268.71676)
		(size 0.4572)
		(drill 0.2032)
		(layers "F.Cu" "B.Cu")
		(net "GND")
	)
	(via
		(at 98.122994 -287.28924)
		(size 0.4572)
		(drill 0.2032)
		(layers "F.Cu" "B.Cu")
		(net "GND")
	)
	(via
		(at 169.352214 -314.616592)
		(size 0.4572)
		(drill 0.2032)
		(layers "F.Cu" "B.Cu")
		(net "GND")
	)
	(via
		(at 448.8942 -117.193822)
		(size 0.508)
		(drill 0.254)
		(layers "F.Cu" "B.Cu")
		(net "GND")
	)
	(via
		(at 96.243394 -269.38351)
		(size 0.4572)
		(drill 0.2032)
		(layers "F.Cu" "B.Cu")
		(net "GND")
	)
	(via
		(at 127.147066 -226.831144)
		(size 0.4572)
		(drill 0.2032)
		(layers "F.Cu" "B.Cu")
		(net "GND")
	)
	(via
		(at 365.799116 -282.405836)
		(size 0.4572)
		(drill 0.2032)
		(layers "F.Cu" "B.Cu")
		(net "GND")
	)
	(via
		(at 353.941634 -216.25052)
		(size 0.4572)
		(drill 0.2032)
		(layers "F.Cu" "B.Cu")
		(net "GND")
	)
	(via
		(at 48.854614 -213.46668)
		(size 0.4572)
		(drill 0.2032)
		(layers "F.Cu" "B.Cu")
		(net "GND")
	)
	(via
		(at 201.737214 -238.116618)
		(size 0.4572)
		(drill 0.2032)
		(layers "F.Cu" "B.Cu")
		(net "GND")
	)
	(via
		(at 139.004294 -278.336502)
		(size 0.4572)
		(drill 0.2032)
		(layers "F.Cu" "B.Cu")
		(net "GND")
	)
	(via
		(at 76.250038 -436.347362)
		(size 0.4572)
		(drill 0.2032)
		(layers "F.Cu" "B.Cu")
		(net "GND")
	)
	(via
		(at 455.011282 -306.96662)
		(size 0.4572)
		(drill 0.2032)
		(layers "F.Cu" "B.Cu")
		(net "GND")
	)
	(via
		(at 417.292282 -204.116686)
		(size 0.4572)
		(drill 0.2032)
		(layers "F.Cu" "B.Cu")
		(net "GND")
	)
	(via
		(at 125.847348 -279.964134)
		(size 0.4572)
		(drill 0.2032)
		(layers "F.Cu" "B.Cu")
		(net "GND")
	)
	(via
		(at 328.288396 -404.51786)
		(size 0.4572)
		(drill 0.254)
		(layers "F.Cu" "B.Cu")
		(net "GND")
	)
	(via
		(at 91.704922 -334.494124)
		(size 0.508)
		(drill 0.254)
		(layers "F.Cu" "B.Cu")
		(net "GND")
	)
	(via
		(at 199.527414 -194.766692)
		(size 0.4572)
		(drill 0.2032)
		(layers "F.Cu" "B.Cu")
		(net "GND")
	)
	(via
		(at 260.90626 -129.710688)
		(size 0.508)
		(drill 0.254)
		(layers "F.Cu" "B.Cu")
		(net "GND")
	)
	(via
		(at 78.250034 -434.899562)
		(size 0.4572)
		(drill 0.2032)
		(layers "F.Cu" "B.Cu")
		(net "GND")
	)
	(via
		(at 88.724994 -262.872474)
		(size 0.4572)
		(drill 0.2032)
		(layers "F.Cu" "B.Cu")
		(net "GND")
	)
	(via
		(at 445.577214 -208.366614)
		(size 0.4572)
		(drill 0.2032)
		(layers "F.Cu" "B.Cu")
		(net "GND")
	)
	(via
		(at 127.430022 -409.396184)
		(size 0.4572)
		(drill 0.254)
		(layers "F.Cu" "B.Cu")
		(net "GND")
	)
	(via
		(at 352.334322 -182.68569)
		(size 0.508)
		(drill 0.254)
		(layers "F.Cu" "B.Cu")
		(net "GND")
	)
	(via
		(at 464.764882 -215.166702)
		(size 0.4572)
		(drill 0.2032)
		(layers "F.Cu" "B.Cu")
		(net "GND")
	)
	(via
		(at 349.352616 -276.708616)
		(size 0.4572)
		(drill 0.2032)
		(layers "F.Cu" "B.Cu")
		(net "GND")
	)
	(via
		(at 345.483434 -243.922804)
		(size 0.4572)
		(drill 0.2032)
		(layers "F.Cu" "B.Cu")
		(net "GND")
	)
	(via
		(at 164.188902 -409.396184)
		(size 0.4572)
		(drill 0.254)
		(layers "F.Cu" "B.Cu")
		(net "GND")
	)
	(via
		(at 415.648648 -171.462954)
		(size 0.49022)
		(drill 0.254)
		(layers "F.Cu" "B.Cu")
		(net "GND")
	)
	(via
		(at 175.286416 -236.416596)
		(size 0.4572)
		(drill 0.2032)
		(layers "F.Cu" "B.Cu")
		(net "GND")
	)
	(via
		(at 331.067918 -54.089046)
		(size 0.4572)
		(drill 0.2032)
		(layers "F.Cu" "B.Cu")
		(net "GND")
	)
	(via
		(at 337.40598 -335.187036)
		(size 0.49022)
		(drill 0.254)
		(layers "F.Cu" "B.Cu")
		(net "GND")
	)
	(via
		(at 270.063214 -276.366732)
		(size 0.4572)
		(drill 0.2032)
		(layers "F.Cu" "B.Cu")
		(net "GND")
	)
	(via
		(at 262.519414 -267.016738)
		(size 0.4572)
		(drill 0.2032)
		(layers "F.Cu" "B.Cu")
		(net "GND")
	)
	(via
		(at 107.24134 -56.248808)
		(size 0.508)
		(drill 0.254)
		(layers "F.Cu" "B.Cu")
		(net "GND")
	)
	(via
		(at 190.093346 -276.366732)
		(size 0.4572)
		(drill 0.2032)
		(layers "F.Cu" "B.Cu")
		(net "GND")
	)
	(via
		(at 102.895654 -252.798834)
		(size 0.4572)
		(drill 0.2032)
		(layers "F.Cu" "B.Cu")
		(net "GND")
	)
	(via
		(at 350.512126 -44.78782)
		(size 0.49022)
		(drill 0.254)
		(layers "F.Cu" "B.Cu")
		(net "GND")
	)
	(via
		(at 362.979462 -279.150318)
		(size 0.4572)
		(drill 0.2032)
		(layers "F.Cu" "B.Cu")
		(net "GND")
	)
	(via
		(at 370.51488 -43.144948)
		(size 0.508)
		(drill 0.254)
		(layers "F.Cu" "B.Cu")
		(net "GND")
	)
	(via
		(at 85.325712 -237.411768)
		(size 0.4572)
		(drill 0.2032)
		(layers "F.Cu" "B.Cu")
		(net "GND")
	)
	(via
		(at 427.045882 -288.266632)
		(size 0.4572)
		(drill 0.2032)
		(layers "F.Cu" "B.Cu")
		(net "GND")
	)
	(via
		(at 446.274952 -392.971274)
		(size 0.6604)
		(drill 0.3302)
		(layers "F.Cu" "B.Cu")
		(net "GND")
	)
	(via
		(at 105.85577 -246.66956)
		(size 0.4572)
		(drill 0.2032)
		(layers "F.Cu" "B.Cu")
		(net "GND")
	)
	(via
		(at 51.830478 -407.00452)
		(size 0.4064)
		(drill 0.2032)
		(layers "F.Cu" "B.Cu")
		(net "GND")
	)
	(via
		(at 438.85104 -106.78541)
		(size 0.508)
		(drill 0.254)
		(layers "F.Cu" "B.Cu")
		(net "GND")
	)
	(via
		(at 6.541008 -51.631596)
		(size 0.508)
		(drill 0.254)
		(layers "F.Cu" "B.Cu")
		(net "GND")
	)
	(via
		(at 330.990448 -400.858228)
		(size 0.4064)
		(drill 0.2032)
		(layers "F.Cu" "B.Cu")
		(net "GND")
	)
	(via
		(at 176.238154 -351.414588)
		(size 0.508)
		(drill 0.254)
		(layers "F.Cu" "B.Cu")
		(net "GND")
	)
	(via
		(at 257.185414 -217.716608)
		(size 0.4572)
		(drill 0.2032)
		(layers "F.Cu" "B.Cu")
		(net "GND")
	)
	(via
		(at 56.398414 -305.266598)
		(size 0.4572)
		(drill 0.2032)
		(layers "F.Cu" "B.Cu")
		(net "GND")
	)
	(via
		(at 409.349956 -438.499758)
		(size 0.4572)
		(drill 0.2032)
		(layers "F.Cu" "B.Cu")
		(net "GND")
	)
	(via
		(at 455.011282 -194.766692)
		(size 0.4572)
		(drill 0.2032)
		(layers "F.Cu" "B.Cu")
		(net "GND")
	)
	(via
		(at 23.386034 -379.193552)
		(size 0.508)
		(drill 0.254)
		(layers "F.Cu" "B.Cu")
		(net "GND")
	)
	(via
		(at 33.767014 -239.81664)
		(size 0.4572)
		(drill 0.2032)
		(layers "F.Cu" "B.Cu")
		(net "GND")
	)
	(via
		(at 56.9849 -363.736128)
		(size 0.508)
		(drill 0.254)
		(layers "F.Cu" "B.Cu")
		(net "GND")
	)
	(via
		(at 103.291894 -283.219906)
		(size 0.4572)
		(drill 0.2032)
		(layers "F.Cu" "B.Cu")
		(net "GND")
	)
	(via
		(at 236.289596 -251.520198)
		(size 0.508)
		(drill 0.254)
		(layers "F.Cu" "B.Cu")
		(net "GND")
	)
	(via
		(at 344.25001 -435.0512)
		(size 0.4572)
		(drill 0.2032)
		(layers "F.Cu" "B.Cu")
		(net "GND")
	)
	(via
		(at 233.09072 -44.449746)
		(size 0.508)
		(drill 0.254)
		(layers "F.Cu" "B.Cu")
		(net "GND")
	)
	(via
		(at 370.763038 -201.20991)
		(size 0.6604)
		(drill 0.3302)
		(layers "F.Cu" "B.Cu")
		(net "GND")
	)
	(via
		(at 96.008698 -329.61453)
		(size 0.6604)
		(drill 0.3302)
		(layers "F.Cu" "B.Cu")
		(net "GND")
	)
	(via
		(at 274.163282 -228.766624)
		(size 0.4572)
		(drill 0.2032)
		(layers "F.Cu" "B.Cu")
		(net "GND")
	)
	(via
		(at 417.997894 -171.068238)
		(size 0.49022)
		(drill 0.254)
		(layers "F.Cu" "B.Cu")
		(net "GND")
	)
	(via
		(at 405.893524 -6.586474)
		(size 0.508)
		(drill 0.254)
		(layers "F.Cu" "B.Cu")
		(net "GND")
	)
	(via
		(at 414.070292 -172.174154)
		(size 0.49022)
		(drill 0.254)
		(layers "F.Cu" "B.Cu")
		(net "GND")
	)
	(via
		(at 73.139808 -10.155936)
		(size 0.508)
		(drill 0.254)
		(layers "F.Cu" "B.Cu")
		(net "GND")
	)
	(via
		(at 33.767014 -221.116652)
		(size 0.4572)
		(drill 0.2032)
		(layers "F.Cu" "B.Cu")
		(net "GND")
	)
	(via
		(at 396.20444 -60.960508)
		(size 0.508)
		(drill 0.254)
		(layers "F.Cu" "B.Cu")
		(net "GND")
	)
	(via
		(at 294.904414 -223.666558)
		(size 0.4572)
		(drill 0.2032)
		(layers "F.Cu" "B.Cu")
		(net "GND")
	)
	(via
		(at 128.666748 -260.430772)
		(size 0.4572)
		(drill 0.2032)
		(layers "F.Cu" "B.Cu")
		(net "GND")
	)
	(via
		(at 266.619482 -232.166668)
		(size 0.4572)
		(drill 0.2032)
		(layers "F.Cu" "B.Cu")
		(net "GND")
	)
	(via
		(at 91.544648 -274.266914)
		(size 0.4572)
		(drill 0.2032)
		(layers "F.Cu" "B.Cu")
		(net "GND")
	)
	(via
		(at 102.30612 -126.840488)
		(size 0.508)
		(drill 0.254)
		(layers "F.Cu" "B.Cu")
		(net "GND")
	)
	(via
		(at 307.782214 -216.016586)
		(size 0.4572)
		(drill 0.2032)
		(layers "F.Cu" "B.Cu")
		(net "GND")
	)
	(via
		(at 93.314266 -220.319854)
		(size 0.4572)
		(drill 0.2032)
		(layers "F.Cu" "B.Cu")
		(net "GND")
	)
	(via
		(at 54.508146 -270.416782)
		(size 0.4572)
		(drill 0.2032)
		(layers "F.Cu" "B.Cu")
		(net "GND")
	)
	(via
		(at 447.467482 -299.316648)
		(size 0.4572)
		(drill 0.2032)
		(layers "F.Cu" "B.Cu")
		(net "GND")
	)
	(via
		(at 154.999182 -406.370536)
		(size 0.4572)
		(drill 0.254)
		(layers "F.Cu" "B.Cu")
		(net "GND")
	)
	(via
		(at 311.666382 -207.51673)
		(size 0.4572)
		(drill 0.2032)
		(layers "F.Cu" "B.Cu")
		(net "GND")
	)
	(via
		(at 321.250056 -434.899562)
		(size 0.4572)
		(drill 0.2032)
		(layers "F.Cu" "B.Cu")
		(net "GND")
	)
	(via
		(at 184.919112 -26.788872)
		(size 0.508)
		(drill 0.254)
		(layers "F.Cu" "B.Cu")
		(net "GND")
	)
	(via
		(at 447.467482 -305.266598)
		(size 0.4572)
		(drill 0.2032)
		(layers "F.Cu" "B.Cu")
		(net "GND")
	)
	(via
		(at 96.243394 -279.150318)
		(size 0.4572)
		(drill 0.2032)
		(layers "F.Cu" "B.Cu")
		(net "GND")
	)
	(via
		(at 122.447812 -233.34218)
		(size 0.4572)
		(drill 0.2032)
		(layers "F.Cu" "B.Cu")
		(net "GND")
	)
	(via
		(at 23.250652 -391.007346)
		(size 0.508)
		(drill 0.254)
		(layers "F.Cu" "B.Cu")
		(net "GND")
	)
	(via
		(at 417.077652 -235.566712)
		(size 0.4572)
		(drill 0.2032)
		(layers "F.Cu" "B.Cu")
		(net "GND")
	)
	(via
		(at 42.9006 -386.20954)
		(size 0.508)
		(drill 0.254)
		(layers "F.Cu" "B.Cu")
		(net "GND")
	)
	(via
		(at 180.339746 -281.466798)
		(size 0.4572)
		(drill 0.2032)
		(layers "F.Cu" "B.Cu")
		(net "GND")
	)
	(via
		(at 338.73694 -404.51786)
		(size 0.4572)
		(drill 0.254)
		(layers "F.Cu" "B.Cu")
		(net "GND")
	)
	(via
		(at 291.460682 -205.816708)
		(size 0.4572)
		(drill 0.2032)
		(layers "F.Cu" "B.Cu")
		(net "GND")
	)
	(via
		(at 435.823614 -225.36658)
		(size 0.4572)
		(drill 0.2032)
		(layers "F.Cu" "B.Cu")
		(net "GND")
	)
	(via
		(at 137.975594 -400.858228)
		(size 0.4064)
		(drill 0.2032)
		(layers "F.Cu" "B.Cu")
		(net "GND")
	)
	(via
		(at 352.641916 -287.28924)
		(size 0.4572)
		(drill 0.2032)
		(layers "F.Cu" "B.Cu")
		(net "GND")
	)
	(via
		(at 390.349994 -437.49976)
		(size 0.4572)
		(drill 0.2032)
		(layers "F.Cu" "B.Cu")
		(net "GND")
	)
	(via
		(at 46.964346 -212.616796)
		(size 0.4572)
		(drill 0.2032)
		(layers "F.Cu" "B.Cu")
		(net "GND")
	)
	(via
		(at 445.577214 -306.116736)
		(size 0.4572)
		(drill 0.2032)
		(layers "F.Cu" "B.Cu")
		(net "GND")
	)
	(via
		(at 342.303862 -261.244842)
		(size 0.4572)
		(drill 0.2032)
		(layers "F.Cu" "B.Cu")
		(net "GND")
	)
	(via
		(at 261.285482 -238.116618)
		(size 0.4572)
		(drill 0.2032)
		(layers "F.Cu" "B.Cu")
		(net "GND")
	)
	(via
		(at 50.845466 -404.51786)
		(size 0.4572)
		(drill 0.254)
		(layers "F.Cu" "B.Cu")
		(net "GND")
	)
	(via
		(at 172.795946 -300.166786)
		(size 0.4572)
		(drill 0.2032)
		(layers "F.Cu" "B.Cu")
		(net "GND")
	)
	(via
		(at 182.549546 -304.416714)
		(size 0.4572)
		(drill 0.2032)
		(layers "F.Cu" "B.Cu")
		(net "GND")
	)
	(via
		(at 13.345414 -286.56661)
		(size 0.4572)
		(drill 0.2032)
		(layers "F.Cu" "B.Cu")
		(net "GND")
	)
	(via
		(at 28.433014 -238.116618)
		(size 0.4572)
		(drill 0.2032)
		(layers "F.Cu" "B.Cu")
		(net "GND")
	)
	(via
		(at 353.68865 -400.328638)
		(size 0.508)
		(drill 0.254)
		(layers "F.Cu" "B.Cu")
		(net "GND")
	)
	(via
		(at 176.896014 -314.616592)
		(size 0.4572)
		(drill 0.2032)
		(layers "F.Cu" "B.Cu")
		(net "GND")
	)
	(via
		(at 209.54492 -102.93604)
		(size 0.508)
		(drill 0.254)
		(layers "F.Cu" "B.Cu")
		(net "GND")
	)
	(via
		(at 22.123146 -296.766742)
		(size 0.4572)
		(drill 0.2032)
		(layers "F.Cu" "B.Cu")
		(net "GND")
	)
	(via
		(at 131.015994 -284.033722)
		(size 0.4572)
		(drill 0.2032)
		(layers "F.Cu" "B.Cu")
		(net "GND")
	)
	(via
		(at 380.31801 -410.030168)
		(size 0.4064)
		(drill 0.2032)
		(layers "F.Cu" "B.Cu")
		(net "GND")
	)
	(via
		(at 135.135366 -216.25052)
		(size 0.4572)
		(drill 0.2032)
		(layers "F.Cu" "B.Cu")
		(net "GND")
	)
	(via
		(at 51.064414 -215.166702)
		(size 0.4572)
		(drill 0.2032)
		(layers "F.Cu" "B.Cu")
		(net "GND")
	)
	(via
		(at 339.37448 -231.714548)
		(size 0.4572)
		(drill 0.2032)
		(layers "F.Cu" "B.Cu")
		(net "GND")
	)
	(via
		(at 339.014816 -253.919736)
		(size 0.4572)
		(drill 0.2032)
		(layers "F.Cu" "B.Cu")
		(net "GND")
	)
	(via
		(at 51.064414 -306.96662)
		(size 0.4572)
		(drill 0.2032)
		(layers "F.Cu" "B.Cu")
		(net "GND")
	)
	(via
		(at 424.974766 -364.071662)
		(size 0.49022)
		(drill 0.254)
		(layers "F.Cu" "B.Cu")
		(net "GND")
	)
	(via
		(at 335.615534 -241.481102)
		(size 0.4572)
		(drill 0.2032)
		(layers "F.Cu" "B.Cu")
		(net "GND")
	)
	(via
		(at 25.514554 -399.974816)
		(size 0.508)
		(drill 0.254)
		(layers "F.Cu" "B.Cu")
		(net "GND")
	)
	(via
		(at 87.675466 -238.225584)
		(size 0.4572)
		(drill 0.2032)
		(layers "F.Cu" "B.Cu")
		(net "GND")
	)
	(via
		(at 337.025234 -247.178322)
		(size 0.4572)
		(drill 0.2032)
		(layers "F.Cu" "B.Cu")
		(net "GND")
	)
	(via
		(at 426.595032 -402.30552)
		(size 0.508)
		(drill 0.254)
		(layers "F.Cu" "B.Cu")
		(net "GND")
	)
	(via
		(at 447.987674 -70.997318)
		(size 0.508)
		(drill 0.254)
		(layers "F.Cu" "B.Cu")
		(net "GND")
	)
	(via
		(at 375.667016 -265.314176)
		(size 0.4572)
		(drill 0.2032)
		(layers "F.Cu" "B.Cu")
		(net "GND")
	)
	(via
		(at 35.976814 -230.466646)
		(size 0.4572)
		(drill 0.2032)
		(layers "F.Cu" "B.Cu")
		(net "GND")
	)
	(via
		(at 46.964346 -216.016586)
		(size 0.4572)
		(drill 0.2032)
		(layers "F.Cu" "B.Cu")
		(net "GND")
	)
	(via
		(at 342.773762 -258.80314)
		(size 0.4572)
		(drill 0.2032)
		(layers "F.Cu" "B.Cu")
		(net "GND")
	)
	(via
		(at 87.675212 -215.436704)
		(size 0.4572)
		(drill 0.2032)
		(layers "F.Cu" "B.Cu")
		(net "GND")
	)
	(via
		(at 117.397784 -292.95598)
		(size 0.508)
		(drill 0.254)
		(layers "F.Cu" "B.Cu")
		(net "GND")
	)
	(via
		(at 332.250034 -430.299622)
		(size 0.4572)
		(drill 0.2032)
		(layers "F.Cu" "B.Cu")
		(net "GND")
	)
	(via
		(at 13.345414 -238.116618)
		(size 0.4572)
		(drill 0.2032)
		(layers "F.Cu" "B.Cu")
		(net "GND")
	)
	(via
		(at 277.607014 -267.016738)
		(size 0.4572)
		(drill 0.2032)
		(layers "F.Cu" "B.Cu")
		(net "GND")
	)
	(via
		(at 424.836082 -262.76681)
		(size 0.4572)
		(drill 0.2032)
		(layers "F.Cu" "B.Cu")
		(net "GND")
	)
	(via
		(at 165.013894 -236.416596)
		(size 0.4572)
		(drill 0.2032)
		(layers "F.Cu" "B.Cu")
		(net "GND")
	)
	(via
		(at 90.964766 -234.15625)
		(size 0.4572)
		(drill 0.2032)
		(layers "F.Cu" "B.Cu")
		(net "GND")
	)
	(via
		(at 185.611008 -351.55632)
		(size 0.508)
		(drill 0.254)
		(layers "F.Cu" "B.Cu")
		(net "GND")
	)
	(via
		(at 159.918146 -317.166752)
		(size 0.4572)
		(drill 0.2032)
		(layers "F.Cu" "B.Cu")
		(net "GND")
	)
	(via
		(at 325.225156 -401.492212)
		(size 0.4572)
		(drill 0.254)
		(layers "F.Cu" "B.Cu")
		(net "GND")
	)
	(via
		(at 110.23092 -246.36476)
		(size 0.4572)
		(drill 0.2032)
		(layers "F.Cu" "B.Cu")
		(net "GND")
	)
	(via
		(at 190.093346 -298.466764)
		(size 0.4572)
		(drill 0.2032)
		(layers "F.Cu" "B.Cu")
		(net "GND")
	)
	(via
		(at 430.489614 -233.016806)
		(size 0.4572)
		(drill 0.2032)
		(layers "F.Cu" "B.Cu")
		(net "GND")
	)
	(via
		(at 352.214942 -292.94836)
		(size 0.508)
		(drill 0.254)
		(layers "F.Cu" "B.Cu")
		(net "GND")
	)
	(via
		(at 345.415108 -73.03516)
		(size 0.508)
		(drill 0.254)
		(layers "F.Cu" "B.Cu")
		(net "GND")
	)
	(via
		(at 369.506754 -179.423568)
		(size 0.508)
		(drill 0.254)
		(layers "F.Cu" "B.Cu")
		(net "GND")
	)
	(via
		(at 300.238414 -278.066754)
		(size 0.4572)
		(drill 0.2032)
		(layers "F.Cu" "B.Cu")
		(net "GND")
	)
	(via
		(at 92.047822 -335.129124)
		(size 0.508)
		(drill 0.254)
		(layers "F.Cu" "B.Cu")
		(net "GND")
	)
	(via
		(at 159.918146 -234.716574)
		(size 0.4572)
		(drill 0.2032)
		(layers "F.Cu" "B.Cu")
		(net "GND")
	)
	(via
		(at 363.809534 -220.319854)
		(size 0.4572)
		(drill 0.2032)
		(layers "F.Cu" "B.Cu")
		(net "GND")
	)
	(via
		(at 417.98875 -151.12873)
		(size 0.508)
		(drill 0.254)
		(layers "F.Cu" "B.Cu")
		(net "GND")
	)
	(via
		(at 417.289742 -151.944324)
		(size 0.508)
		(drill 0.254)
		(layers "F.Cu" "B.Cu")
		(net "GND")
	)
	(via
		(at 296.794682 -291.666676)
		(size 0.4572)
		(drill 0.2032)
		(layers "F.Cu" "B.Cu")
		(net "GND")
	)
	(via
		(at 348.882462 -261.244842)
		(size 0.4572)
		(drill 0.2032)
		(layers "F.Cu" "B.Cu")
		(net "GND")
	)
	(via
		(at 92.014294 -275.08073)
		(size 0.4572)
		(drill 0.2032)
		(layers "F.Cu" "B.Cu")
		(net "GND")
	)
	(via
		(at 194.193414 -289.966654)
		(size 0.4572)
		(drill 0.2032)
		(layers "F.Cu" "B.Cu")
		(net "GND")
	)
	(via
		(at 124.327412 -231.714548)
		(size 0.4572)
		(drill 0.2032)
		(layers "F.Cu" "B.Cu")
		(net "GND")
	)
	(via
		(at 154.637994 -407.00452)
		(size 0.4064)
		(drill 0.2032)
		(layers "F.Cu" "B.Cu")
		(net "GND")
	)
	(via
		(at 238.577628 -135.64108)
		(size 0.508)
		(drill 0.254)
		(layers "F.Cu" "B.Cu")
		(net "GND")
	)
	(via
		(at 434.02504 -122.988578)
		(size 0.508)
		(drill 0.254)
		(layers "F.Cu" "B.Cu")
		(net "GND")
	)
	(via
		(at 35.976814 -280.61666)
		(size 0.4572)
		(drill 0.2032)
		(layers "F.Cu" "B.Cu")
		(net "GND")
	)
	(via
		(at 184.439814 -200.716642)
		(size 0.4572)
		(drill 0.2032)
		(layers "F.Cu" "B.Cu")
		(net "GND")
	)
	(via
		(at 307.782214 -301.866808)
		(size 0.4572)
		(drill 0.2032)
		(layers "F.Cu" "B.Cu")
		(net "GND")
	)
	(via
		(at 44.754546 -295.06672)
		(size 0.4572)
		(drill 0.2032)
		(layers "F.Cu" "B.Cu")
		(net "GND")
	)
	(via
		(at 344.183462 -267.755878)
		(size 0.4572)
		(drill 0.2032)
		(layers "F.Cu" "B.Cu")
		(net "GND")
	)
	(via
		(at 101.302566 -219.506038)
		(size 0.4572)
		(drill 0.2032)
		(layers "F.Cu" "B.Cu")
		(net "GND")
	)
	(via
		(at 401.019772 -18.235422)
		(size 0.508)
		(drill 0.254)
		(layers "F.Cu" "B.Cu")
		(net "GND")
	)
	(via
		(at 49.493932 -173.824392)
		(size 0.508)
		(drill 0.254)
		(layers "F.Cu" "B.Cu")
		(net "GND")
	)
	(via
		(at 135.605266 -223.575626)
		(size 0.4572)
		(drill 0.2032)
		(layers "F.Cu" "B.Cu")
		(net "GND")
	)
	(via
		(at 279.816814 -201.56678)
		(size 0.4572)
		(drill 0.2032)
		(layers "F.Cu" "B.Cu")
		(net "GND")
	)
	(via
		(at 336.195162 -281.59202)
		(size 0.4572)
		(drill 0.2032)
		(layers "F.Cu" "B.Cu")
		(net "GND")
	)
	(via
		(at 310.207914 -208.366614)
		(size 0.4572)
		(drill 0.2032)
		(layers "F.Cu" "B.Cu")
		(net "GND")
	)
	(via
		(at 91.434666 -217.064336)
		(size 0.4572)
		(drill 0.2032)
		(layers "F.Cu" "B.Cu")
		(net "GND")
	)
	(via
		(at 100.832666 -220.319854)
		(size 0.4572)
		(drill 0.2032)
		(layers "F.Cu" "B.Cu")
		(net "GND")
	)
	(via
		(at 164.101526 -403.249892)
		(size 0.4572)
		(drill 0.254)
		(layers "F.Cu" "B.Cu")
		(net "GND")
	)
	(via
		(at 59.842146 -281.466798)
		(size 0.4572)
		(drill 0.2032)
		(layers "F.Cu" "B.Cu")
		(net "GND")
	)
	(via
		(at 171.562014 -299.316648)
		(size 0.4572)
		(drill 0.2032)
		(layers "F.Cu" "B.Cu")
		(net "GND")
	)
	(via
		(at 11.135614 -266.1666)
		(size 0.4572)
		(drill 0.2032)
		(layers "F.Cu" "B.Cu")
		(net "GND")
	)
	(via
		(at 383.020062 -407.638504)
		(size 0.4572)
		(drill 0.254)
		(layers "F.Cu" "B.Cu")
		(net "GND")
	)
	(via
		(at 434.589682 -230.466646)
		(size 0.4572)
		(drill 0.2032)
		(layers "F.Cu" "B.Cu")
		(net "GND")
	)
	(via
		(at 22.123146 -208.366614)
		(size 0.4572)
		(drill 0.2032)
		(layers "F.Cu" "B.Cu")
		(net "GND")
	)
	(via
		(at 412.465774 -29.877258)
		(size 0.508)
		(drill 0.254)
		(layers "F.Cu" "B.Cu")
		(net "GND")
	)
	(via
		(at 262.519414 -210.916774)
		(size 0.4572)
		(drill 0.2032)
		(layers "F.Cu" "B.Cu")
		(net "GND")
	)
	(via
		(at 330.252578 -45.160946)
		(size 0.4572)
		(drill 0.2032)
		(layers "F.Cu" "B.Cu")
		(net "GND")
	)
	(via
		(at 427.045882 -267.866622)
		(size 0.4572)
		(drill 0.2032)
		(layers "F.Cu" "B.Cu")
		(net "GND")
	)
	(via
		(at 90.25001 -427.699678)
		(size 0.4572)
		(drill 0.2032)
		(layers "F.Cu" "B.Cu")
		(net "GND")
	)
	(via
		(at 346.063062 -275.8948)
		(size 0.4572)
		(drill 0.2032)
		(layers "F.Cu" "B.Cu")
		(net "GND")
	)
	(via
		(at 257.185414 -203.266802)
		(size 0.4572)
		(drill 0.2032)
		(layers "F.Cu" "B.Cu")
		(net "GND")
	)
	(via
		(at 125.986794 -407.00452)
		(size 0.4064)
		(drill 0.2032)
		(layers "F.Cu" "B.Cu")
		(net "GND")
	)
	(via
		(at 368.978434 -226.017328)
		(size 0.4572)
		(drill 0.2032)
		(layers "F.Cu" "B.Cu")
		(net "GND")
	)
	(via
		(at 157.45587 -236.416596)
		(size 0.4572)
		(drill 0.2032)
		(layers "F.Cu" "B.Cu")
		(net "GND")
	)
	(via
		(at 182.549546 -315.46673)
		(size 0.4572)
		(drill 0.2032)
		(layers "F.Cu" "B.Cu")
		(net "GND")
	)
	(via
		(at 225.917506 -365.236252)
		(size 0.508)
		(drill 0.254)
		(layers "F.Cu" "B.Cu")
		(net "GND")
	)
	(via
		(at 88.255094 -253.919736)
		(size 0.4572)
		(drill 0.2032)
		(layers "F.Cu" "B.Cu")
		(net "GND")
	)
	(via
		(at 229.59822 -51.53279)
		(size 0.508)
		(drill 0.254)
		(layers "F.Cu" "B.Cu")
		(net "GND")
	)
	(via
		(at 165.252146 -261.916672)
		(size 0.4572)
		(drill 0.2032)
		(layers "F.Cu" "B.Cu")
		(net "GND")
	)
	(via
		(at 374.257062 -271.011396)
		(size 0.4572)
		(drill 0.2032)
		(layers "F.Cu" "B.Cu")
		(net "GND")
	)
	(via
		(at 63.942214 -267.866622)
		(size 0.4572)
		(drill 0.2032)
		(layers "F.Cu" "B.Cu")
		(net "GND")
	)
	(via
		(at 82.84083 -342.557354)
		(size 0.49022)
		(drill 0.254)
		(layers "F.Cu" "B.Cu")
		(net "GND")
	)
	(via
		(at 129.136394 -261.244842)
		(size 0.4572)
		(drill 0.2032)
		(layers "F.Cu" "B.Cu")
		(net "GND")
	)
	(via
		(at 46.076362 -345.72321)
		(size 0.508)
		(drill 0.254)
		(layers "F.Cu" "B.Cu")
		(net "GND")
	)
	(via
		(at 453.121014 -272.116804)
		(size 0.4572)
		(drill 0.2032)
		(layers "F.Cu" "B.Cu")
		(net "GND")
	)
	(via
		(at 171.562014 -221.116652)
		(size 0.4572)
		(drill 0.2032)
		(layers "F.Cu" "B.Cu")
		(net "GND")
	)
	(via
		(at 396.898114 -4.95173)
		(size 0.508)
		(drill 0.254)
		(layers "F.Cu" "B.Cu")
		(net "GND")
	)
	(via
		(at 194.193414 -239.81664)
		(size 0.4572)
		(drill 0.2032)
		(layers "F.Cu" "B.Cu")
		(net "GND")
	)
	(via
		(at 176.901348 -350.754188)
		(size 0.508)
		(drill 0.254)
		(layers "F.Cu" "B.Cu")
		(net "GND")
	)
	(via
		(at 104.275128 -295.031414)
		(size 0.508)
		(drill 0.254)
		(layers "F.Cu" "B.Cu")
		(net "GND")
	)
	(via
		(at 56.744362 -150.93188)
		(size 0.508)
		(drill 0.254)
		(layers "F.Cu" "B.Cu")
		(net "GND")
	)
	(via
		(at 199.527414 -210.066636)
		(size 0.4572)
		(drill 0.2032)
		(layers "F.Cu" "B.Cu")
		(net "GND")
	)
	(via
		(at 445.577214 -217.716608)
		(size 0.4572)
		(drill 0.2032)
		(layers "F.Cu" "B.Cu")
		(net "GND")
	)
	(via
		(at 380.835916 -264.50036)
		(size 0.4572)
		(drill 0.2032)
		(layers "F.Cu" "B.Cu")
		(net "GND")
	)
	(via
		(at 309.45074 -406.370536)
		(size 0.4572)
		(drill 0.254)
		(layers "F.Cu" "B.Cu")
		(net "GND")
	)
	(via
		(at 257.185414 -287.416748)
		(size 0.4572)
		(drill 0.2032)
		(layers "F.Cu" "B.Cu")
		(net "GND")
	)
	(via
		(at 332.435962 -255.547622)
		(size 0.4572)
		(drill 0.2032)
		(layers "F.Cu" "B.Cu")
		(net "GND")
	)
	(via
		(at 449.677282 -213.46668)
		(size 0.4572)
		(drill 0.2032)
		(layers "F.Cu" "B.Cu")
		(net "GND")
	)
	(via
		(at 376.22734 -335.976214)
		(size 0.49022)
		(drill 0.254)
		(layers "F.Cu" "B.Cu")
		(net "GND")
	)
	(via
		(at 309.992014 -244.916706)
		(size 0.4572)
		(drill 0.2032)
		(layers "F.Cu" "B.Cu")
		(net "GND")
	)
	(via
		(at 460.664814 -217.716608)
		(size 0.4572)
		(drill 0.2032)
		(layers "F.Cu" "B.Cu")
		(net "GND")
	)
	(via
		(at 317.29426 -404.51786)
		(size 0.4572)
		(drill 0.254)
		(layers "F.Cu" "B.Cu")
		(net "GND")
	)
	(via
		(at 348.77248 -228.45903)
		(size 0.4572)
		(drill 0.2032)
		(layers "F.Cu" "B.Cu")
		(net "GND")
	)
	(via
		(at 405.648414 -278.066754)
		(size 0.4572)
		(drill 0.2032)
		(layers "F.Cu" "B.Cu")
		(net "GND")
	)
	(via
		(at 81.48955 -40.401748)
		(size 0.508)
		(drill 0.254)
		(layers "F.Cu" "B.Cu")
		(net "GND")
	)
	(via
		(at 63.726314 -238.116618)
		(size 0.4572)
		(drill 0.2032)
		(layers "F.Cu" "B.Cu")
		(net "GND")
	)
	(via
		(at 264.729214 -233.016806)
		(size 0.4572)
		(drill 0.2032)
		(layers "F.Cu" "B.Cu")
		(net "GND")
	)
	(via
		(at 172.795946 -216.016586)
		(size 0.4572)
		(drill 0.2032)
		(layers "F.Cu" "B.Cu")
		(net "GND")
	)
	(via
		(at 302.448214 -300.166786)
		(size 0.4572)
		(drill 0.2032)
		(layers "F.Cu" "B.Cu")
		(net "GND")
	)
	(via
		(at 261.285482 -286.56661)
		(size 0.4572)
		(drill 0.2032)
		(layers "F.Cu" "B.Cu")
		(net "GND")
	)
	(via
		(at 443.367414 -260.21665)
		(size 0.4572)
		(drill 0.2032)
		(layers "F.Cu" "B.Cu")
		(net "GND")
	)
	(via
		(at 459.695042 -78.418436)
		(size 0.508)
		(drill 0.254)
		(layers "F.Cu" "B.Cu")
		(net "GND")
	)
	(via
		(at 283.916882 -310.366664)
		(size 0.4572)
		(drill 0.2032)
		(layers "F.Cu" "B.Cu")
		(net "GND")
	)
	(via
		(at 84.495894 -258.80314)
		(size 0.4572)
		(drill 0.2032)
		(layers "F.Cu" "B.Cu")
		(net "GND")
	)
	(via
		(at 91.544648 -254.733552)
		(size 0.4572)
		(drill 0.2032)
		(layers "F.Cu" "B.Cu")
		(net "GND")
	)
	(via
		(at 14.579346 -267.016738)
		(size 0.4572)
		(drill 0.2032)
		(layers "F.Cu" "B.Cu")
		(net "GND")
	)
	(via
		(at 181.755796 -110.175294)
		(size 0.4572)
		(drill 0.254)
		(layers "F.Cu" "B.Cu")
		(net "GND")
	)
	(via
		(at 29.666946 -214.316564)
		(size 0.4572)
		(drill 0.2032)
		(layers "F.Cu" "B.Cu")
		(net "GND")
	)
	(via
		(at 9.245346 -289.11677)
		(size 0.4572)
		(drill 0.2032)
		(layers "F.Cu" "B.Cu")
		(net "GND")
	)
	(via
		(at 9.245346 -208.366614)
		(size 0.4572)
		(drill 0.2032)
		(layers "F.Cu" "B.Cu")
		(net "GND")
	)
	(via
		(at 335.6737 -401.492212)
		(size 0.4572)
		(drill 0.254)
		(layers "F.Cu" "B.Cu")
		(net "GND")
	)
	(via
		(at 419.502082 -224.516696)
		(size 0.4572)
		(drill 0.2032)
		(layers "F.Cu" "B.Cu")
		(net "GND")
	)
	(via
		(at 264.729214 -290.816792)
		(size 0.4572)
		(drill 0.2032)
		(layers "F.Cu" "B.Cu")
		(net "GND")
	)
	(via
		(at 197.637146 -267.016738)
		(size 0.4572)
		(drill 0.2032)
		(layers "F.Cu" "B.Cu")
		(net "GND")
	)
	(via
		(at 277.607014 -298.466764)
		(size 0.4572)
		(drill 0.2032)
		(layers "F.Cu" "B.Cu")
		(net "GND")
	)
	(via
		(at 399.349976 -432.747166)
		(size 0.4572)
		(drill 0.2032)
		(layers "F.Cu" "B.Cu")
		(net "GND")
	)
	(via
		(at 457.221082 -196.466714)
		(size 0.4572)
		(drill 0.2032)
		(layers "F.Cu" "B.Cu")
		(net "GND")
	)
	(via
		(at 257.185414 -281.466798)
		(size 0.4572)
		(drill 0.2032)
		(layers "F.Cu" "B.Cu")
		(net "GND")
	)
	(via
		(at 434.589682 -219.41663)
		(size 0.4572)
		(drill 0.2032)
		(layers "F.Cu" "B.Cu")
		(net "GND")
	)
	(via
		(at 139.474448 -257.98907)
		(size 0.4572)
		(drill 0.2032)
		(layers "F.Cu" "B.Cu")
		(net "GND")
	)
	(via
		(at 28.433014 -221.116652)
		(size 0.4572)
		(drill 0.2032)
		(layers "F.Cu" "B.Cu")
		(net "GND")
	)
	(via
		(at 308.10454 -401.492212)
		(size 0.4572)
		(drill 0.254)
		(layers "F.Cu" "B.Cu")
		(net "GND")
	)
	(via
		(at 127.726948 -253.919736)
		(size 0.4572)
		(drill 0.2032)
		(layers "F.Cu" "B.Cu")
		(net "GND")
	)
	(via
		(at 411.958282 -282.316682)
		(size 0.4572)
		(drill 0.2032)
		(layers "F.Cu" "B.Cu")
		(net "GND")
	)
	(via
		(at 464.764882 -226.216718)
		(size 0.4572)
		(drill 0.2032)
		(layers "F.Cu" "B.Cu")
		(net "GND")
	)
	(via
		(at 41.310814 -282.316682)
		(size 0.4572)
		(drill 0.2032)
		(layers "F.Cu" "B.Cu")
		(net "GND")
	)
	(via
		(at 337.49488 -233.34218)
		(size 0.4572)
		(drill 0.2032)
		(layers "F.Cu" "B.Cu")
		(net "GND")
	)
	(via
		(at 163.964112 -78.390242)
		(size 0.508)
		(drill 0.254)
		(layers "F.Cu" "B.Cu")
		(net "GND")
	)
	(via
		(at 161.808414 -239.81664)
		(size 0.4572)
		(drill 0.2032)
		(layers "F.Cu" "B.Cu")
		(net "GND")
	)
	(via
		(at 283.916882 -269.566644)
		(size 0.4572)
		(drill 0.2032)
		(layers "F.Cu" "B.Cu")
		(net "GND")
	)
	(via
		(at 103.40975 -361.944412)
		(size 0.508)
		(drill 0.254)
		(layers "F.Cu" "B.Cu")
		(net "GND")
	)
	(via
		(at 184.439814 -204.116686)
		(size 0.4572)
		(drill 0.2032)
		(layers "F.Cu" "B.Cu")
		(net "GND")
	)
	(via
		(at 179.105814 -232.166668)
		(size 0.4572)
		(drill 0.2032)
		(layers "F.Cu" "B.Cu")
		(net "GND")
	)
	(via
		(at 29.666946 -292.516814)
		(size 0.4572)
		(drill 0.2032)
		(layers "F.Cu" "B.Cu")
		(net "GND")
	)
	(via
		(at 361.608624 -339.208872)
		(size 0.508)
		(drill 0.254)
		(layers "F.Cu" "B.Cu")
		(net "GND")
	)
	(via
		(at 162.745674 -407.00452)
		(size 0.4064)
		(drill 0.2032)
		(layers "F.Cu" "B.Cu")
		(net "GND")
	)
	(via
		(at 171.383198 -353.19335)
		(size 0.49022)
		(drill 0.254)
		(layers "F.Cu" "B.Cu")
		(net "GND")
	)
	(via
		(at 332.180692 -73.040494)
		(size 0.508)
		(drill 0.254)
		(layers "F.Cu" "B.Cu")
		(net "GND")
	)
	(via
		(at 362.95076 -68.400168)
		(size 0.508)
		(drill 0.254)
		(layers "F.Cu" "B.Cu")
		(net "GND")
	)
	(via
		(at 374.22074 -106.299508)
		(size 0.508)
		(drill 0.254)
		(layers "F.Cu" "B.Cu")
		(net "GND")
	)
	(via
		(at 141.968982 -338.210652)
		(size 0.508)
		(drill 0.254)
		(layers "F.Cu" "B.Cu")
		(net "GND")
	)
	(via
		(at 321.21348 -23.551896)
		(size 0.508)
		(drill 0.254)
		(layers "F.Cu" "B.Cu")
		(net "GND")
	)
	(via
		(at 171.562014 -226.216718)
		(size 0.4572)
		(drill 0.2032)
		(layers "F.Cu" "B.Cu")
		(net "GND")
	)
	(via
		(at 439.923682 -278.916638)
		(size 0.4572)
		(drill 0.2032)
		(layers "F.Cu" "B.Cu")
		(net "GND")
	)
	(via
		(at 348.128844 -44.796964)
		(size 0.49022)
		(drill 0.254)
		(layers "F.Cu" "B.Cu")
		(net "GND")
	)
	(via
		(at 353.001834 -222.761556)
		(size 0.4572)
		(drill 0.2032)
		(layers "F.Cu" "B.Cu")
		(net "GND")
	)
	(via
		(at 307.782214 -300.166786)
		(size 0.4572)
		(drill 0.2032)
		(layers "F.Cu" "B.Cu")
		(net "GND")
	)
	(via
		(at 292.694614 -301.866808)
		(size 0.4572)
		(drill 0.2032)
		(layers "F.Cu" "B.Cu")
		(net "GND")
	)
	(via
		(at 346.338906 -84.846922)
		(size 0.508)
		(drill 0.254)
		(layers "F.Cu" "B.Cu")
		(net "GND")
	)
	(via
		(at 428.279814 -236.416596)
		(size 0.4572)
		(drill 0.2032)
		(layers "F.Cu" "B.Cu")
		(net "GND")
	)
	(via
		(at 11.135614 -310.366664)
		(size 0.4572)
		(drill 0.2032)
		(layers "F.Cu" "B.Cu")
		(net "GND")
	)
	(via
		(at 444.0936 -9.464548)
		(size 0.508)
		(drill 0.254)
		(layers "F.Cu" "B.Cu")
		(net "GND")
	)
	(via
		(at 257.584194 -323.417946)
		(size 0.4572)
		(drill 0.2032)
		(layers "F.Cu" "B.Cu")
		(net "GND")
	)
	(via
		(at 453.121014 -295.06672)
		(size 0.4572)
		(drill 0.2032)
		(layers "F.Cu" "B.Cu")
		(net "GND")
	)
	(via
		(at 160.764474 -410.030168)
		(size 0.4064)
		(drill 0.2032)
		(layers "F.Cu" "B.Cu")
		(net "GND")
	)
	(via
		(at 471.03538 -28.544266)
		(size 0.508)
		(drill 0.254)
		(layers "F.Cu" "B.Cu")
		(net "GND")
	)
	(via
		(at 405.648414 -307.816758)
		(size 0.4572)
		(drill 0.2032)
		(layers "F.Cu" "B.Cu")
		(net "GND")
	)
	(via
		(at 9.245346 -272.116804)
		(size 0.4572)
		(drill 0.2032)
		(layers "F.Cu" "B.Cu")
		(net "GND")
	)
	(via
		(at 458.455014 -283.166566)
		(size 0.4572)
		(drill 0.2032)
		(layers "F.Cu" "B.Cu")
		(net "GND")
	)
	(via
		(at 186.649614 -198.166736)
		(size 0.4572)
		(drill 0.2032)
		(layers "F.Cu" "B.Cu")
		(net "GND")
	)
	(via
		(at 424.181016 -137.93851)
		(size 0.508)
		(drill 0.254)
		(layers "F.Cu" "B.Cu")
		(net "GND")
	)
	(via
		(at 193.598292 -32.939736)
		(size 0.508)
		(drill 0.254)
		(layers "F.Cu" "B.Cu")
		(net "GND")
	)
	(via
		(at 340.894416 -265.314176)
		(size 0.4572)
		(drill 0.2032)
		(layers "F.Cu" "B.Cu")
		(net "GND")
	)
	(via
		(at 357.700326 -214.622634)
		(size 0.4572)
		(drill 0.2032)
		(layers "F.Cu" "B.Cu")
		(net "GND")
	)
	(via
		(at 377.076462 -254.733552)
		(size 0.4572)
		(drill 0.2032)
		(layers "F.Cu" "B.Cu")
		(net "GND")
	)
	(via
		(at 449.677282 -230.466646)
		(size 0.4572)
		(drill 0.2032)
		(layers "F.Cu" "B.Cu")
		(net "GND")
	)
	(via
		(at 226.897692 -135.73252)
		(size 0.508)
		(drill 0.254)
		(layers "F.Cu" "B.Cu")
		(net "GND")
	)
	(via
		(at 357.700834 -226.017328)
		(size 0.4572)
		(drill 0.2032)
		(layers "F.Cu" "B.Cu")
		(net "GND")
	)
	(via
		(at 194.2719 -63.447168)
		(size 0.508)
		(drill 0.254)
		(layers "F.Cu" "B.Cu")
		(net "GND")
	)
	(via
		(at 219.438982 -70.336918)
		(size 0.508)
		(drill 0.254)
		(layers "F.Cu" "B.Cu")
		(net "GND")
	)
	(via
		(at 376.606562 -289.807142)
		(size 0.4572)
		(drill 0.2032)
		(layers "F.Cu" "B.Cu")
		(net "GND")
	)
	(via
		(at 449.677282 -200.716642)
		(size 0.4572)
		(drill 0.2032)
		(layers "F.Cu" "B.Cu")
		(net "GND")
	)
	(via
		(at 149.349968 -437.34736)
		(size 0.4572)
		(drill 0.2032)
		(layers "F.Cu" "B.Cu")
		(net "GND")
	)
	(via
		(at 104.591866 -213.732618)
		(size 0.4572)
		(drill 0.2032)
		(layers "F.Cu" "B.Cu")
		(net "GND")
	)
	(via
		(at 102.712266 -213.732618)
		(size 0.4572)
		(drill 0.2032)
		(layers "F.Cu" "B.Cu")
		(net "GND")
	)
	(via
		(at 121.508266 -213.732618)
		(size 0.4572)
		(drill 0.2032)
		(layers "F.Cu" "B.Cu")
		(net "GND")
	)
	(via
		(at 128.556512 -357.47579)
		(size 0.508)
		(drill 0.254)
		(layers "F.Cu" "B.Cu")
		(net "GND")
	)
	(via
		(at 296.794682 -272.966688)
		(size 0.4572)
		(drill 0.2032)
		(layers "F.Cu" "B.Cu")
		(net "GND")
	)
	(via
		(at 424.836082 -271.266666)
		(size 0.4572)
		(drill 0.2032)
		(layers "F.Cu" "B.Cu")
		(net "GND")
	)
	(via
		(at 310.6674 -32.3342)
		(size 0.508)
		(drill 0.254)
		(layers "F.Cu" "B.Cu")
		(net "GND")
	)
	(via
		(at 135.245348 -270.19758)
		(size 0.4572)
		(drill 0.2032)
		(layers "F.Cu" "B.Cu")
		(net "GND")
	)
	(via
		(at 136.726422 -335.957672)
		(size 0.508)
		(drill 0.254)
		(layers "F.Cu" "B.Cu")
		(net "GND")
	)
	(via
		(at 414.493964 -441.225432)
		(size 0.508)
		(drill 0.254)
		(layers "F.Cu" "B.Cu")
		(net "GND")
	)
	(via
		(at 113.519966 -239.039654)
		(size 0.4572)
		(drill 0.2032)
		(layers "F.Cu" "B.Cu")
		(net "GND")
	)
	(via
		(at 427.045882 -210.066636)
		(size 0.4572)
		(drill 0.2032)
		(layers "F.Cu" "B.Cu")
		(net "GND")
	)
	(via
		(at 119.97309 -334.282034)
		(size 0.49022)
		(drill 0.254)
		(layers "F.Cu" "B.Cu")
		(net "GND")
	)
	(via
		(at 26.223214 -301.01667)
		(size 0.4572)
		(drill 0.2032)
		(layers "F.Cu" "B.Cu")
		(net "GND")
	)
	(via
		(at 281.707082 -200.716642)
		(size 0.4572)
		(drill 0.2032)
		(layers "F.Cu" "B.Cu")
		(net "GND")
	)
	(via
		(at 428.279814 -220.266768)
		(size 0.4572)
		(drill 0.2032)
		(layers "F.Cu" "B.Cu")
		(net "GND")
	)
	(via
		(at 266.619482 -226.216718)
		(size 0.4572)
		(drill 0.2032)
		(layers "F.Cu" "B.Cu")
		(net "GND")
	)
	(via
		(at 365.689134 -213.732618)
		(size 0.4572)
		(drill 0.2032)
		(layers "F.Cu" "B.Cu")
		(net "GND")
	)
	(via
		(at 257.185414 -265.316716)
		(size 0.4572)
		(drill 0.2032)
		(layers "F.Cu" "B.Cu")
		(net "GND")
	)
	(via
		(at 208.900268 -193.641726)
		(size 0.508)
		(drill 0.254)
		(layers "F.Cu" "B.Cu")
		(net "GND")
	)
	(via
		(at 31.876746 -301.866808)
		(size 0.4572)
		(drill 0.2032)
		(layers "F.Cu" "B.Cu")
		(net "GND")
	)
	(via
		(at 279.816814 -309.51678)
		(size 0.4572)
		(drill 0.2032)
		(layers "F.Cu" "B.Cu")
		(net "GND")
	)
	(via
		(at 341.105998 -46.100746)
		(size 0.4572)
		(drill 0.2032)
		(layers "F.Cu" "B.Cu")
		(net "GND")
	)
	(via
		(at 210.514946 -339.56498)
		(size 0.508)
		(drill 0.254)
		(layers "F.Cu" "B.Cu")
		(net "GND")
	)
	(via
		(at 281.707082 -232.166668)
		(size 0.4572)
		(drill 0.2032)
		(layers "F.Cu" "B.Cu")
		(net "GND")
	)
	(via
		(at 382.605534 -223.575626)
		(size 0.4572)
		(drill 0.2032)
		(layers "F.Cu" "B.Cu")
		(net "GND")
	)
	(via
		(at 409.748482 -286.74441)
		(size 0.4572)
		(drill 0.2032)
		(layers "F.Cu" "B.Cu")
		(net "GND")
	)
	(via
		(at 459.228952 -323.429376)
		(size 0.4572)
		(drill 0.2032)
		(layers "F.Cu" "B.Cu")
		(net "GND")
	)
	(via
		(at 41.310814 -308.666642)
		(size 0.4572)
		(drill 0.2032)
		(layers "F.Cu" "B.Cu")
		(net "GND")
	)
	(via
		(at 464.764882 -306.96662)
		(size 0.4572)
		(drill 0.2032)
		(layers "F.Cu" "B.Cu")
		(net "GND")
	)
	(via
		(at 435.823614 -248.31675)
		(size 0.4572)
		(drill 0.2032)
		(layers "F.Cu" "B.Cu")
		(net "GND")
	)
	(via
		(at 210.514946 -229.616762)
		(size 0.4572)
		(drill 0.2032)
		(layers "F.Cu" "B.Cu")
		(net "GND")
	)
	(via
		(at 277.607014 -296.766742)
		(size 0.4572)
		(drill 0.2032)
		(layers "F.Cu" "B.Cu")
		(net "GND")
	)
	(via
		(at 121.47296 -15.526766)
		(size 0.508)
		(drill 0.254)
		(layers "F.Cu" "B.Cu")
		(net "GND")
	)
	(via
		(at 134.195566 -216.25052)
		(size 0.4572)
		(drill 0.2032)
		(layers "F.Cu" "B.Cu")
		(net "GND")
	)
	(via
		(at 132.350002 -426.54728)
		(size 0.4572)
		(drill 0.2032)
		(layers "F.Cu" "B.Cu")
		(net "GND")
	)
	(via
		(at 191.983614 -213.46668)
		(size 0.4572)
		(drill 0.2032)
		(layers "F.Cu" "B.Cu")
		(net "GND")
	)
	(via
		(at 55.254906 -409.396184)
		(size 0.4572)
		(drill 0.254)
		(layers "F.Cu" "B.Cu")
		(net "GND")
	)
	(via
		(at 287.006792 -16.963644)
		(size 0.508)
		(drill 0.254)
		(layers "F.Cu" "B.Cu")
		(net "GND")
	)
	(via
		(at 59.626246 -206.666592)
		(size 0.4572)
		(drill 0.2032)
		(layers "F.Cu" "B.Cu")
		(net "GND")
	)
	(via
		(at 324.98919 -26.861008)
		(size 0.508)
		(drill 0.254)
		(layers "F.Cu" "B.Cu")
		(net "GND")
	)
	(via
		(at 40.256968 -7.215124)
		(size 0.508)
		(drill 0.254)
		(layers "F.Cu" "B.Cu")
		(net "GND")
	)
	(via
		(at 378.33681 -410.030168)
		(size 0.4064)
		(drill 0.2032)
		(layers "F.Cu" "B.Cu")
		(net "GND")
	)
	(via
		(at 13.345414 -306.96662)
		(size 0.4572)
		(drill 0.2032)
		(layers "F.Cu" "B.Cu")
		(net "GND")
	)
	(via
		(at 434.589682 -312.91657)
		(size 0.4572)
		(drill 0.2032)
		(layers "F.Cu" "B.Cu")
		(net "GND")
	)
	(via
		(at 110.952788 -295.03878)
		(size 0.508)
		(drill 0.254)
		(layers "F.Cu" "B.Cu")
		(net "GND")
	)
	(via
		(at 138.34999 -429.147224)
		(size 0.4572)
		(drill 0.2032)
		(layers "F.Cu" "B.Cu")
		(net "GND")
	)
	(via
		(at 202.971146 -195.616576)
		(size 0.4572)
		(drill 0.2032)
		(layers "F.Cu" "B.Cu")
		(net "GND")
	)
	(via
		(at 62.051946 -242.3668)
		(size 0.4572)
		(drill 0.2032)
		(layers "F.Cu" "B.Cu")
		(net "GND")
	)
	(via
		(at 96.33585 -410.664152)
		(size 0.4572)
		(drill 0.254)
		(layers "F.Cu" "B.Cu")
		(net "GND")
	)
	(via
		(at 411.349952 -432.747166)
		(size 0.4572)
		(drill 0.2032)
		(layers "F.Cu" "B.Cu")
		(net "GND")
	)
	(via
		(at 94.363794 -264.50036)
		(size 0.4572)
		(drill 0.2032)
		(layers "F.Cu" "B.Cu")
		(net "GND")
	)
	(via
		(at 92.954094 -289.807142)
		(size 0.4572)
		(drill 0.2032)
		(layers "F.Cu" "B.Cu")
		(net "GND")
	)
	(via
		(at 100.832412 -228.45903)
		(size 0.4572)
		(drill 0.2032)
		(layers "F.Cu" "B.Cu")
		(net "GND")
	)
	(via
		(at 413.192214 -214.316564)
		(size 0.4572)
		(drill 0.2032)
		(layers "F.Cu" "B.Cu")
		(net "GND")
	)
	(via
		(at 417.997894 -179.704238)
		(size 0.49022)
		(drill 0.254)
		(layers "F.Cu" "B.Cu")
		(net "GND")
	)
	(via
		(at 9.245346 -246.616728)
		(size 0.4572)
		(drill 0.2032)
		(layers "F.Cu" "B.Cu")
		(net "GND")
	)
	(via
		(at 180.64988 -131.280408)
		(size 0.508)
		(drill 0.254)
		(layers "F.Cu" "B.Cu")
		(net "GND")
	)
	(via
		(at 383.075434 -226.017328)
		(size 0.4572)
		(drill 0.2032)
		(layers "F.Cu" "B.Cu")
		(net "GND")
	)
	(via
		(at 97.653094 -276.708616)
		(size 0.4572)
		(drill 0.2032)
		(layers "F.Cu" "B.Cu")
		(net "GND")
	)
	(via
		(at 422.945814 -270.416782)
		(size 0.4572)
		(drill 0.2032)
		(layers "F.Cu" "B.Cu")
		(net "GND")
	)
	(via
		(at 322.064888 -410.030168)
		(size 0.4064)
		(drill 0.2032)
		(layers "F.Cu" "B.Cu")
		(net "GND")
	)
	(via
		(at 416.128962 -360.148378)
		(size 0.49022)
		(drill 0.254)
		(layers "F.Cu" "B.Cu")
		(net "GND")
	)
	(via
		(at 311.882282 -239.81664)
		(size 0.4572)
		(drill 0.2032)
		(layers "F.Cu" "B.Cu")
		(net "GND")
	)
	(via
		(at 283.916882 -314.616592)
		(size 0.4572)
		(drill 0.2032)
		(layers "F.Cu" "B.Cu")
		(net "GND")
	)
	(via
		(at 336.085434 -230.900478)
		(size 0.4572)
		(drill 0.2032)
		(layers "F.Cu" "B.Cu")
		(net "GND")
	)
	(via
		(at 337.478116 -404.51786)
		(size 0.4572)
		(drill 0.254)
		(layers "F.Cu" "B.Cu")
		(net "GND")
	)
	(via
		(at 401.399502 -410.664152)
		(size 0.4572)
		(drill 0.254)
		(layers "F.Cu" "B.Cu")
		(net "GND")
	)
	(via
		(at 88.250014 -425.547282)
		(size 0.4572)
		(drill 0.2032)
		(layers "F.Cu" "B.Cu")
		(net "GND")
	)
	(via
		(at 126.350014 -430.299622)
		(size 0.4572)
		(drill 0.2032)
		(layers "F.Cu" "B.Cu")
		(net "GND")
	)
	(via
		(at 69.250052 -427.699678)
		(size 0.4572)
		(drill 0.2032)
		(layers "F.Cu" "B.Cu")
		(net "GND")
	)
	(via
		(at 330.09967 -341.063072)
		(size 0.49022)
		(drill 0.254)
		(layers "F.Cu" "B.Cu")
		(net "GND")
	)
	(via
		(at 380.835662 -261.244842)
		(size 0.4572)
		(drill 0.2032)
		(layers "F.Cu" "B.Cu")
		(net "GND")
	)
	(via
		(at 123.020582 -400.224244)
		(size 0.4572)
		(drill 0.254)
		(layers "F.Cu" "B.Cu")
		(net "GND")
	)
	(via
		(at 421.684704 -58.6994)
		(size 0.508)
		(drill 0.254)
		(layers "F.Cu" "B.Cu")
		(net "GND")
	)
	(via
		(at 442.133482 -258.516628)
		(size 0.4572)
		(drill 0.2032)
		(layers "F.Cu" "B.Cu")
		(net "GND")
	)
	(via
		(at 184.955688 -114.17554)
		(size 0.4572)
		(drill 0.254)
		(layers "F.Cu" "B.Cu")
		(net "GND")
	)
	(via
		(at 266.619482 -210.066636)
		(size 0.4572)
		(drill 0.2032)
		(layers "F.Cu" "B.Cu")
		(net "GND")
	)
	(via
		(at 93.633798 -410.030168)
		(size 0.4064)
		(drill 0.2032)
		(layers "F.Cu" "B.Cu")
		(net "GND")
	)
	(via
		(at 382.245616 -270.19758)
		(size 0.4572)
		(drill 0.2032)
		(layers "F.Cu" "B.Cu")
		(net "GND")
	)
	(via
		(at 356.173532 -46.802802)
		(size 0.508)
		(drill 0.254)
		(layers "F.Cu" "B.Cu")
		(net "GND")
	)
	(via
		(at 125.847094 -262.058658)
		(size 0.4572)
		(drill 0.2032)
		(layers "F.Cu" "B.Cu")
		(net "GND")
	)
	(via
		(at 187.74918 -357.03637)
		(size 0.508)
		(drill 0.254)
		(layers "F.Cu" "B.Cu")
		(net "GND")
	)
	(via
		(at 261.285482 -200.716642)
		(size 0.4572)
		(drill 0.2032)
		(layers "F.Cu" "B.Cu")
		(net "GND")
	)
	(via
		(at 108.930948 -265.314176)
		(size 0.4572)
		(drill 0.2032)
		(layers "F.Cu" "B.Cu")
		(net "GND")
	)
	(via
		(at 91.544648 -259.616956)
		(size 0.4572)
		(drill 0.2032)
		(layers "F.Cu" "B.Cu")
		(net "GND")
	)
	(via
		(at 386.083302 -406.370536)
		(size 0.4572)
		(drill 0.254)
		(layers "F.Cu" "B.Cu")
		(net "GND")
	)
	(via
		(at 56.867044 -9.424924)
		(size 0.508)
		(drill 0.254)
		(layers "F.Cu" "B.Cu")
		(net "GND")
	)
	(via
		(at 84.20481 -339.624416)
		(size 0.508)
		(drill 0.254)
		(layers "F.Cu" "B.Cu")
		(net "GND")
	)
	(via
		(at 210.514946 -208.366614)
		(size 0.4572)
		(drill 0.2032)
		(layers "F.Cu" "B.Cu")
		(net "GND")
	)
	(via
		(at 428.279814 -221.96679)
		(size 0.4572)
		(drill 0.2032)
		(layers "F.Cu" "B.Cu")
		(net "GND")
	)
	(via
		(at 462.555082 -194.766692)
		(size 0.4572)
		(drill 0.2032)
		(layers "F.Cu" "B.Cu")
		(net "GND")
	)
	(via
		(at 61.212222 -162.17646)
		(size 0.508)
		(drill 0.254)
		(layers "F.Cu" "B.Cu")
		(net "GND")
	)
	(via
		(at 276.373082 -286.56661)
		(size 0.4572)
		(drill 0.2032)
		(layers "F.Cu" "B.Cu")
		(net "GND")
	)
	(via
		(at 338.73694 -400.224244)
		(size 0.4572)
		(drill 0.254)
		(layers "F.Cu" "B.Cu")
		(net "GND")
	)
	(via
		(at 298.41952 -150.533608)
		(size 0.508)
		(drill 0.254)
		(layers "F.Cu" "B.Cu")
		(net "GND")
	)
	(via
		(at 133.195314 -410.030168)
		(size 0.4064)
		(drill 0.2032)
		(layers "F.Cu" "B.Cu")
		(net "GND")
	)
	(via
		(at 121.216166 -403.249892)
		(size 0.4572)
		(drill 0.254)
		(layers "F.Cu" "B.Cu")
		(net "GND")
	)
	(via
		(at 59.842146 -261.916672)
		(size 0.4572)
		(drill 0.2032)
		(layers "F.Cu" "B.Cu")
		(net "GND")
	)
	(via
		(at 358.170734 -244.73662)
		(size 0.4572)
		(drill 0.2032)
		(layers "F.Cu" "B.Cu")
		(net "GND")
	)
	(via
		(at 64.35725 -400.224244)
		(size 0.4572)
		(drill 0.254)
		(layers "F.Cu" "B.Cu")
		(net "GND")
	)
	(via
		(at 287.360614 -281.466798)
		(size 0.4572)
		(drill 0.2032)
		(layers "F.Cu" "B.Cu")
		(net "GND")
	)
	(via
		(at 434.589682 -277.216616)
		(size 0.4572)
		(drill 0.2032)
		(layers "F.Cu" "B.Cu")
		(net "GND")
	)
	(via
		(at 136.294114 -343.48293)
		(size 0.49022)
		(drill 0.254)
		(layers "F.Cu" "B.Cu")
		(net "GND")
	)
	(via
		(at 207.391 -121.1072)
		(size 0.508)
		(drill 0.254)
		(layers "F.Cu" "B.Cu")
		(net "GND")
	)
	(via
		(at 184.155588 -105.375456)
		(size 0.4572)
		(drill 0.254)
		(layers "F.Cu" "B.Cu")
		(net "GND")
	)
	(via
		(at 310.207914 -206.666592)
		(size 0.4572)
		(drill 0.2032)
		(layers "F.Cu" "B.Cu")
		(net "GND")
	)
	(via
		(at 296.794682 -249.166634)
		(size 0.4572)
		(drill 0.2032)
		(layers "F.Cu" "B.Cu")
		(net "GND")
	)
	(via
		(at 340.08314 -409.396184)
		(size 0.4572)
		(drill 0.254)
		(layers "F.Cu" "B.Cu")
		(net "GND")
	)
	(via
		(at 100.942394 -254.733552)
		(size 0.4572)
		(drill 0.2032)
		(layers "F.Cu" "B.Cu")
		(net "GND")
	)
	(via
		(at 124.327412 -247.992138)
		(size 0.4572)
		(drill 0.2032)
		(layers "F.Cu" "B.Cu")
		(net "GND")
	)
	(via
		(at 179.105814 -221.116652)
		(size 0.4572)
		(drill 0.2032)
		(layers "F.Cu" "B.Cu")
		(net "GND")
	)
	(via
		(at 438.033414 -244.916706)
		(size 0.4572)
		(drill 0.2032)
		(layers "F.Cu" "B.Cu")
		(net "GND")
	)
	(via
		(at 56.398414 -316.316614)
		(size 0.4572)
		(drill 0.2032)
		(layers "F.Cu" "B.Cu")
		(net "GND")
	)
	(via
		(at 2.764536 -284.910022)
		(size 0.508)
		(drill 0.254)
		(layers "F.Cu" "B.Cu")
		(net "GND")
	)
	(via
		(at 58.824114 -291.666676)
		(size 0.4572)
		(drill 0.2032)
		(layers "F.Cu" "B.Cu")
		(net "GND")
	)
	(via
		(at 114.099594 -272.639282)
		(size 0.4572)
		(drill 0.2032)
		(layers "F.Cu" "B.Cu")
		(net "GND")
	)
	(via
		(at 432.50104 -124.512578)
		(size 0.508)
		(drill 0.254)
		(layers "F.Cu" "B.Cu")
		(net "GND")
	)
	(via
		(at 129.606548 -271.825212)
		(size 0.4572)
		(drill 0.2032)
		(layers "F.Cu" "B.Cu")
		(net "GND")
	)
	(via
		(at 430.489614 -210.916774)
		(size 0.4572)
		(drill 0.2032)
		(layers "F.Cu" "B.Cu")
		(net "GND")
	)
	(via
		(at 422.909238 -153.609548)
		(size 0.508)
		(drill 0.254)
		(layers "F.Cu" "B.Cu")
		(net "GND")
	)
	(via
		(at 400.018504 -6.586474)
		(size 0.508)
		(drill 0.254)
		(layers "F.Cu" "B.Cu")
		(net "GND")
	)
	(via
		(at 113.52022 -240.66754)
		(size 0.4572)
		(drill 0.2032)
		(layers "F.Cu" "B.Cu")
		(net "GND")
	)
	(via
		(at 179.35575 -111.775494)
		(size 0.4572)
		(drill 0.254)
		(layers "F.Cu" "B.Cu")
		(net "GND")
	)
	(via
		(at 389.903208 -338.964016)
		(size 0.508)
		(drill 0.254)
		(layers "F.Cu" "B.Cu")
		(net "GND")
	)
	(via
		(at 112.580166 -229.272846)
		(size 0.4572)
		(drill 0.2032)
		(layers "F.Cu" "B.Cu")
		(net "GND")
	)
	(via
		(at 331.254608 -407.00452)
		(size 0.4064)
		(drill 0.2032)
		(layers "F.Cu" "B.Cu")
		(net "GND")
	)
	(via
		(at 417.089082 -294.216582)
		(size 0.4572)
		(drill 0.2032)
		(layers "F.Cu" "B.Cu")
		(net "GND")
	)
	(via
		(at 394.349986 -433.899564)
		(size 0.4572)
		(drill 0.2032)
		(layers "F.Cu" "B.Cu")
		(net "GND")
	)
	(via
		(at 16.064484 -323.434456)
		(size 0.4572)
		(drill 0.2032)
		(layers "F.Cu" "B.Cu")
		(net "GND")
	)
	(via
		(at 30.53715 -129.633472)
		(size 0.508)
		(drill 0.254)
		(layers "F.Cu" "B.Cu")
		(net "GND")
	)
	(via
		(at 7.035546 -203.266802)
		(size 0.4572)
		(drill 0.2032)
		(layers "F.Cu" "B.Cu")
		(net "GND")
	)
	(via
		(at 41.310814 -238.116618)
		(size 0.4572)
		(drill 0.2032)
		(layers "F.Cu" "B.Cu")
		(net "GND")
	)
	(via
		(at 129.496312 -234.15625)
		(size 0.4572)
		(drill 0.2032)
		(layers "F.Cu" "B.Cu")
		(net "GND")
	)
	(via
		(at 392.34999 -426.54728)
		(size 0.4572)
		(drill 0.2032)
		(layers "F.Cu" "B.Cu")
		(net "GND")
	)
	(via
		(at 407.858214 -292.516814)
		(size 0.4572)
		(drill 0.2032)
		(layers "F.Cu" "B.Cu")
		(net "GND")
	)
	(via
		(at 70.74408 -187.470288)
		(size 0.508)
		(drill 0.254)
		(layers "F.Cu" "B.Cu")
		(net "GND")
	)
	(via
		(at 58.608214 -303.566576)
		(size 0.4572)
		(drill 0.2032)
		(layers "F.Cu" "B.Cu")
		(net "GND")
	)
	(via
		(at 430.489614 -258.516628)
		(size 0.4572)
		(drill 0.2032)
		(layers "F.Cu" "B.Cu")
		(net "GND")
	)
	(via
		(at 277.607014 -221.96679)
		(size 0.4572)
		(drill 0.2032)
		(layers "F.Cu" "B.Cu")
		(net "GND")
	)
	(via
		(at 411.958282 -250.866656)
		(size 0.4572)
		(drill 0.2032)
		(layers "F.Cu" "B.Cu")
		(net "GND")
	)
	(via
		(at 194.193414 -299.316648)
		(size 0.4572)
		(drill 0.2032)
		(layers "F.Cu" "B.Cu")
		(net "GND")
	)
	(via
		(at 49.290986 -153.644854)
		(size 0.508)
		(drill 0.254)
		(layers "F.Cu" "B.Cu")
		(net "GND")
	)
	(via
		(at 334.477868 -60.627768)
		(size 0.6604)
		(drill 0.3302)
		(layers "F.Cu" "B.Cu")
		(net "GND")
	)
	(via
		(at 60.551822 -150.93188)
		(size 0.508)
		(drill 0.254)
		(layers "F.Cu" "B.Cu")
		(net "GND")
	)
	(via
		(at 115.509294 -273.453098)
		(size 0.4572)
		(drill 0.2032)
		(layers "F.Cu" "B.Cu")
		(net "GND")
	)
	(via
		(at 394.62329 -4.95173)
		(size 0.508)
		(drill 0.254)
		(layers "F.Cu" "B.Cu")
		(net "GND")
	)
	(via
		(at 387.52653 -410.030168)
		(size 0.4064)
		(drill 0.2032)
		(layers "F.Cu" "B.Cu")
		(net "GND")
	)
	(via
		(at 84.55533 -441.225432)
		(size 0.508)
		(drill 0.254)
		(layers "F.Cu" "B.Cu")
		(net "GND")
	)
	(via
		(at 270.063214 -267.016738)
		(size 0.4572)
		(drill 0.2032)
		(layers "F.Cu" "B.Cu")
		(net "GND")
	)
	(via
		(at 372.754144 -366.329214)
		(size 0.508)
		(drill 0.254)
		(layers "F.Cu" "B.Cu")
		(net "GND")
	)
	(via
		(at 216.824814 -295.916604)
		(size 0.4572)
		(drill 0.2032)
		(layers "F.Cu" "B.Cu")
		(net "GND")
	)
	(via
		(at 125.847348 -283.219906)
		(size 0.4572)
		(drill 0.2032)
		(layers "F.Cu" "B.Cu")
		(net "GND")
	)
	(via
		(at 434.589682 -278.916638)
		(size 0.4572)
		(drill 0.2032)
		(layers "F.Cu" "B.Cu")
		(net "GND")
	)
	(via
		(at 46.964346 -220.266768)
		(size 0.4572)
		(drill 0.2032)
		(layers "F.Cu" "B.Cu")
		(net "GND")
	)
	(via
		(at 26.138886 -163.303204)
		(size 0.508)
		(drill 0.254)
		(layers "F.Cu" "B.Cu")
		(net "GND")
	)
	(via
		(at 13.345414 -250.866656)
		(size 0.4572)
		(drill 0.2032)
		(layers "F.Cu" "B.Cu")
		(net "GND")
	)
	(via
		(at 297.87088 -134.076948)
		(size 0.508)
		(drill 0.254)
		(layers "F.Cu" "B.Cu")
		(net "GND")
	)
	(via
		(at 325.225156 -400.224244)
		(size 0.4572)
		(drill 0.254)
		(layers "F.Cu" "B.Cu")
		(net "GND")
	)
	(via
		(at 294.904414 -306.116736)
		(size 0.4572)
		(drill 0.2032)
		(layers "F.Cu" "B.Cu")
		(net "GND")
	)
	(via
		(at 44.432728 -350.874838)
		(size 0.508)
		(drill 0.254)
		(layers "F.Cu" "B.Cu")
		(net "GND")
	)
	(via
		(at 90.570558 -407.00452)
		(size 0.4064)
		(drill 0.2032)
		(layers "F.Cu" "B.Cu")
		(net "GND")
	)
	(via
		(at 422.945814 -283.166566)
		(size 0.4572)
		(drill 0.2032)
		(layers "F.Cu" "B.Cu")
		(net "GND")
	)
	(via
		(at 365.938308 -239.306354)
		(size 0.4572)
		(drill 0.2032)
		(layers "F.Cu" "B.Cu")
		(net "GND")
	)
	(via
		(at 123.497594 -277.522432)
		(size 0.4572)
		(drill 0.2032)
		(layers "F.Cu" "B.Cu")
		(net "GND")
	)
	(via
		(at 59.842146 -216.016586)
		(size 0.4572)
		(drill 0.2032)
		(layers "F.Cu" "B.Cu")
		(net "GND")
	)
	(via
		(at 117.414294 -239.306608)
		(size 0.4572)
		(drill 0.2032)
		(layers "F.Cu" "B.Cu")
		(net "GND")
	)
	(via
		(at 155.977844 -136.556496)
		(size 0.508)
		(drill 0.254)
		(layers "F.Cu" "B.Cu")
		(net "GND")
	)
	(via
		(at 350.806512 -259.696458)
		(size 0.4572)
		(drill 0.2032)
		(layers "F.Cu" "B.Cu")
		(net "GND")
	)
	(via
		(at 279.046686 -12.544552)
		(size 0.508)
		(drill 0.254)
		(layers "F.Cu" "B.Cu")
		(net "GND")
	)
	(via
		(at 25.946608 -130.396996)
		(size 0.508)
		(drill 0.254)
		(layers "F.Cu" "B.Cu")
		(net "GND")
	)
	(via
		(at 187.883546 -276.366732)
		(size 0.4572)
		(drill 0.2032)
		(layers "F.Cu" "B.Cu")
		(net "GND")
	)
	(via
		(at 352.457004 -333.355188)
		(size 0.49022)
		(drill 0.254)
		(layers "F.Cu" "B.Cu")
		(net "GND")
	)
	(via
		(at 319.25006 -438.651396)
		(size 0.4572)
		(drill 0.2032)
		(layers "F.Cu" "B.Cu")
		(net "GND")
	)
	(via
		(at 363.339634 -222.761556)
		(size 0.4572)
		(drill 0.2032)
		(layers "F.Cu" "B.Cu")
		(net "GND")
	)
	(via
		(at 48.854614 -198.166736)
		(size 0.4572)
		(drill 0.2032)
		(layers "F.Cu" "B.Cu")
		(net "GND")
	)
	(via
		(at 41.310814 -272.966688)
		(size 0.4572)
		(drill 0.2032)
		(layers "F.Cu" "B.Cu")
		(net "GND")
	)
	(via
		(at 429.566832 -9.424924)
		(size 0.508)
		(drill 0.254)
		(layers "F.Cu" "B.Cu")
		(net "GND")
	)
	(via
		(at 312.875168 -407.00452)
		(size 0.4064)
		(drill 0.2032)
		(layers "F.Cu" "B.Cu")
		(net "GND")
	)
	(via
		(at 7.264654 -410.855414)
		(size 0.508)
		(drill 0.254)
		(layers "F.Cu" "B.Cu")
		(net "GND")
	)
	(via
		(at 191.983614 -312.91657)
		(size 0.4572)
		(drill 0.2032)
		(layers "F.Cu" "B.Cu")
		(net "GND")
	)
	(via
		(at 261.285482 -284.866588)
		(size 0.4572)
		(drill 0.2032)
		(layers "F.Cu" "B.Cu")
		(net "GND")
	)
	(via
		(at 153.652982 -403.249892)
		(size 0.4572)
		(drill 0.254)
		(layers "F.Cu" "B.Cu")
		(net "GND")
	)
	(via
		(at 274.163282 -232.166668)
		(size 0.4572)
		(drill 0.2032)
		(layers "F.Cu" "B.Cu")
		(net "GND")
	)
	(via
		(at 88.807798 -250.66117)
		(size 0.6604)
		(drill 0.3302)
		(layers "F.Cu" "B.Cu")
		(net "GND")
	)
	(via
		(at 349.822516 -277.522432)
		(size 0.4572)
		(drill 0.2032)
		(layers "F.Cu" "B.Cu")
		(net "GND")
	)
	(via
		(at 100.942394 -261.244842)
		(size 0.4572)
		(drill 0.2032)
		(layers "F.Cu" "B.Cu")
		(net "GND")
	)
	(via
		(at 22.123146 -216.016586)
		(size 0.4572)
		(drill 0.2032)
		(layers "F.Cu" "B.Cu")
		(net "GND")
	)
	(via
		(at 32.947102 -7.215124)
		(size 0.508)
		(drill 0.254)
		(layers "F.Cu" "B.Cu")
		(net "GND")
	)
	(via
		(at 86.735666 -221.94774)
		(size 0.4318)
		(drill 0.2032)
		(layers "F.Cu" "B.Cu")
		(net "GND")
	)
	(via
		(at 382.19888 -341.564722)
		(size 0.508)
		(drill 0.254)
		(layers "F.Cu" "B.Cu")
		(net "GND")
	)
	(via
		(at 392.57097 -407.00452)
		(size 0.4064)
		(drill 0.2032)
		(layers "F.Cu" "B.Cu")
		(net "GND")
	)
	(via
		(at 134.305548 -260.430772)
		(size 0.4572)
		(drill 0.2032)
		(layers "F.Cu" "B.Cu")
		(net "GND")
	)
	(via
		(at 419.705282 -275.516594)
		(size 0.4572)
		(drill 0.2032)
		(layers "F.Cu" "B.Cu")
		(net "GND")
	)
	(via
		(at 160.217358 -238.966756)
		(size 0.4572)
		(drill 0.2032)
		(layers "F.Cu" "B.Cu")
		(net "GND")
	)
	(via
		(at 367.208562 -283.219906)
		(size 0.4572)
		(drill 0.2032)
		(layers "F.Cu" "B.Cu")
		(net "GND")
	)
	(via
		(at 410.4132 -148.351748)
		(size 0.508)
		(drill 0.254)
		(layers "F.Cu" "B.Cu")
		(net "GND")
	)
	(via
		(at 309.992014 -260.21665)
		(size 0.4572)
		(drill 0.2032)
		(layers "F.Cu" "B.Cu")
		(net "GND")
	)
	(via
		(at 108.025946 -331.08392)
		(size 0.508)
		(drill 0.254)
		(layers "F.Cu" "B.Cu")
		(net "GND")
	)
	(via
		(at 176.37506 -33.955228)
		(size 0.508)
		(drill 0.254)
		(layers "F.Cu" "B.Cu")
		(net "GND")
	)
	(via
		(at 123.249944 -360.132376)
		(size 0.508)
		(drill 0.254)
		(layers "F.Cu" "B.Cu")
		(net "GND")
	)
	(via
		(at 270.063214 -270.416782)
		(size 0.4572)
		(drill 0.2032)
		(layers "F.Cu" "B.Cu")
		(net "GND")
	)
	(via
		(at 216.460324 -58.389012)
		(size 0.508)
		(drill 0.254)
		(layers "F.Cu" "B.Cu")
		(net "GND")
	)
	(via
		(at 411.958282 -306.96662)
		(size 0.4572)
		(drill 0.2032)
		(layers "F.Cu" "B.Cu")
		(net "GND")
	)
	(via
		(at 442.133482 -228.766624)
		(size 0.4572)
		(drill 0.2032)
		(layers "F.Cu" "B.Cu")
		(net "GND")
	)
	(via
		(at 337.381088 -410.030168)
		(size 0.4064)
		(drill 0.2032)
		(layers "F.Cu" "B.Cu")
		(net "GND")
	)
	(via
		(at 151.935942 -410.664152)
		(size 0.4572)
		(drill 0.254)
		(layers "F.Cu" "B.Cu")
		(net "GND")
	)
	(via
		(at 240.408968 -116.94414)
		(size 0.508)
		(drill 0.254)
		(layers "F.Cu" "B.Cu")
		(net "GND")
	)
	(via
		(at 384.485134 -238.225584)
		(size 0.4318)
		(drill 0.2032)
		(layers "F.Cu" "B.Cu")
		(net "GND")
	)
	(via
		(at 63.942214 -288.266632)
		(size 0.4572)
		(drill 0.2032)
		(layers "F.Cu" "B.Cu")
		(net "GND")
	)
	(via
		(at 162.842702 -401.492212)
		(size 0.4572)
		(drill 0.254)
		(layers "F.Cu" "B.Cu")
		(net "GND")
	)
	(via
		(at 231.702356 -36.040314)
		(size 0.508)
		(drill 0.254)
		(layers "F.Cu" "B.Cu")
		(net "GND")
	)
	(via
		(at 372.377462 -259.616956)
		(size 0.4572)
		(drill 0.2032)
		(layers "F.Cu" "B.Cu")
		(net "GND")
	)
	(via
		(at 363.809534 -223.575626)
		(size 0.4572)
		(drill 0.2032)
		(layers "F.Cu" "B.Cu")
		(net "GND")
	)
	(via
		(at 122.917712 -243.922804)
		(size 0.4572)
		(drill 0.2032)
		(layers "F.Cu" "B.Cu")
		(net "GND")
	)
	(via
		(at 129.050034 -407.00452)
		(size 0.4064)
		(drill 0.2032)
		(layers "F.Cu" "B.Cu")
		(net "GND")
	)
	(via
		(at 306.548282 -264.466578)
		(size 0.4572)
		(drill 0.2032)
		(layers "F.Cu" "B.Cu")
		(net "GND")
	)
	(via
		(at 422.58488 -157.590236)
		(size 0.508)
		(drill 0.254)
		(layers "F.Cu" "B.Cu")
		(net "GND")
	)
	(via
		(at 415.369502 -404.51786)
		(size 0.4572)
		(drill 0.254)
		(layers "F.Cu" "B.Cu")
		(net "GND")
	)
	(via
		(at 28.433014 -297.616626)
		(size 0.4572)
		(drill 0.2032)
		(layers "F.Cu" "B.Cu")
		(net "GND")
	)
	(via
		(at 411.687772 -17.601438)
		(size 0.508)
		(drill 0.254)
		(layers "F.Cu" "B.Cu")
		(net "GND")
	)
	(via
		(at 195.427346 -242.3668)
		(size 0.4572)
		(drill 0.2032)
		(layers "F.Cu" "B.Cu")
		(net "GND")
	)
	(via
		(at 418.875718 -152.943306)
		(size 0.49022)
		(drill 0.254)
		(layers "F.Cu" "B.Cu")
		(net "GND")
	)
	(via
		(at 56.398414 -278.916638)
		(size 0.4572)
		(drill 0.2032)
		(layers "F.Cu" "B.Cu")
		(net "GND")
	)
	(via
		(at 41.310814 -314.616592)
		(size 0.4572)
		(drill 0.2032)
		(layers "F.Cu" "B.Cu")
		(net "GND")
	)
	(via
		(at 334.205834 -226.017328)
		(size 0.4572)
		(drill 0.2032)
		(layers "F.Cu" "B.Cu")
		(net "GND")
	)
	(via
		(at 21.96846 -50.999898)
		(size 0.508)
		(drill 0.254)
		(layers "F.Cu" "B.Cu")
		(net "GND")
	)
	(via
		(at 138.34999 -426.69968)
		(size 0.4572)
		(drill 0.2032)
		(layers "F.Cu" "B.Cu")
		(net "GND")
	)
	(via
		(at 264.729214 -289.11677)
		(size 0.4572)
		(drill 0.2032)
		(layers "F.Cu" "B.Cu")
		(net "GND")
	)
	(via
		(at 409.748482 -262.76681)
		(size 0.4572)
		(drill 0.2032)
		(layers "F.Cu" "B.Cu")
		(net "GND")
	)
	(via
		(at 84.250022 -438.651396)
		(size 0.4572)
		(drill 0.2032)
		(layers "F.Cu" "B.Cu")
		(net "GND")
	)
	(via
		(at 164.018214 -316.316614)
		(size 0.4572)
		(drill 0.2032)
		(layers "F.Cu" "B.Cu")
		(net "GND")
	)
	(via
		(at 14.579346 -216.016586)
		(size 0.4572)
		(drill 0.2032)
		(layers "F.Cu" "B.Cu")
		(net "GND")
	)
	(via
		(at 445.577214 -251.716794)
		(size 0.4572)
		(drill 0.2032)
		(layers "F.Cu" "B.Cu")
		(net "GND")
	)
	(via
		(at 303.48936 -61.130688)
		(size 0.508)
		(drill 0.254)
		(layers "F.Cu" "B.Cu")
		(net "GND")
	)
	(via
		(at 138.534648 -257.98907)
		(size 0.4572)
		(drill 0.2032)
		(layers "F.Cu" "B.Cu")
		(net "GND")
	)
	(via
		(at 283.916882 -288.266632)
		(size 0.4572)
		(drill 0.2032)
		(layers "F.Cu" "B.Cu")
		(net "GND")
	)
	(via
		(at 367.406428 -332.56601)
		(size 0.49022)
		(drill 0.254)
		(layers "F.Cu" "B.Cu")
		(net "GND")
	)
	(via
		(at 379.896116 -257.98907)
		(size 0.4572)
		(drill 0.2032)
		(layers "F.Cu" "B.Cu")
		(net "GND")
	)
	(via
		(at 107.331764 -393.711684)
		(size 0.508)
		(drill 0.254)
		(layers "F.Cu" "B.Cu")
		(net "GND")
	)
	(via
		(at 302.448214 -296.766742)
		(size 0.4572)
		(drill 0.2032)
		(layers "F.Cu" "B.Cu")
		(net "GND")
	)
	(via
		(at 131.725924 -6.044438)
		(size 0.508)
		(drill 0.254)
		(layers "F.Cu" "B.Cu")
		(net "GND")
	)
	(via
		(at 317.250064 -437.34736)
		(size 0.4572)
		(drill 0.2032)
		(layers "F.Cu" "B.Cu")
		(net "GND")
	)
	(via
		(at 398.336262 -407.638504)
		(size 0.4572)
		(drill 0.254)
		(layers "F.Cu" "B.Cu")
		(net "GND")
	)
	(via
		(at 37.210746 -270.416782)
		(size 0.4572)
		(drill 0.2032)
		(layers "F.Cu" "B.Cu")
		(net "GND")
	)
	(via
		(at 13.866622 -4.872482)
		(size 0.508)
		(drill 0.254)
		(layers "F.Cu" "B.Cu")
		(net "GND")
	)
	(via
		(at 52.789836 -173.737524)
		(size 0.49022)
		(drill 0.254)
		(layers "F.Cu" "B.Cu")
		(net "GND")
	)
	(via
		(at 385.424934 -221.94774)
		(size 0.4572)
		(drill 0.2032)
		(layers "F.Cu" "B.Cu")
		(net "GND")
	)
	(via
		(at 29.111194 -6.597396)
		(size 0.508)
		(drill 0.254)
		(layers "F.Cu" "B.Cu")
		(net "GND")
	)
	(via
		(at 56.558942 -17.61236)
		(size 0.508)
		(drill 0.254)
		(layers "F.Cu" "B.Cu")
		(net "GND")
	)
	(via
		(at 133.556502 -406.370536)
		(size 0.4572)
		(drill 0.254)
		(layers "F.Cu" "B.Cu")
		(net "GND")
	)
	(via
		(at 84.08289 -407.638504)
		(size 0.4572)
		(drill 0.254)
		(layers "F.Cu" "B.Cu")
		(net "GND")
	)
	(via
		(at 378.610622 -403.249892)
		(size 0.4572)
		(drill 0.254)
		(layers "F.Cu" "B.Cu")
		(net "GND")
	)
	(via
		(at 76.697586 -406.370536)
		(size 0.4572)
		(drill 0.254)
		(layers "F.Cu" "B.Cu")
		(net "GND")
	)
	(via
		(at 338.824316 -406.370536)
		(size 0.4572)
		(drill 0.254)
		(layers "F.Cu" "B.Cu")
		(net "GND")
	)
	(via
		(at 281.707082 -264.466578)
		(size 0.4572)
		(drill 0.2032)
		(layers "F.Cu" "B.Cu")
		(net "GND")
	)
	(via
		(at 97.073466 -249.620024)
		(size 0.4572)
		(drill 0.2032)
		(layers "F.Cu" "B.Cu")
		(net "GND")
	)
	(via
		(at 394.349986 -436.347362)
		(size 0.4572)
		(drill 0.2032)
		(layers "F.Cu" "B.Cu")
		(net "GND")
	)
	(via
		(at 443.367414 -223.666558)
		(size 0.4572)
		(drill 0.2032)
		(layers "F.Cu" "B.Cu")
		(net "GND")
	)
	(via
		(at 99.187254 -331.780896)
		(size 0.49022)
		(drill 0.254)
		(layers "F.Cu" "B.Cu")
		(net "GND")
	)
	(via
		(at 337.814158 -84.933536)
		(size 0.508)
		(drill 0.254)
		(layers "F.Cu" "B.Cu")
		(net "GND")
	)
	(via
		(at 270.063214 -296.766742)
		(size 0.4572)
		(drill 0.2032)
		(layers "F.Cu" "B.Cu")
		(net "GND")
	)
	(via
		(at 367.488978 -328.50709)
		(size 0.6604)
		(drill 0.3302)
		(layers "F.Cu" "B.Cu")
		(net "GND")
	)
	(via
		(at 367.208816 -279.964134)
		(size 0.4572)
		(drill 0.2032)
		(layers "F.Cu" "B.Cu")
		(net "GND")
	)
	(via
		(at 61.29401 -404.51786)
		(size 0.4572)
		(drill 0.254)
		(layers "F.Cu" "B.Cu")
		(net "GND")
	)
	(via
		(at 283.916882 -284.866588)
		(size 0.4572)
		(drill 0.2032)
		(layers "F.Cu" "B.Cu")
		(net "GND")
	)
	(via
		(at 5.644642 -98.566478)
		(size 0.508)
		(drill 0.254)
		(layers "F.Cu" "B.Cu")
		(net "GND")
	)
	(via
		(at 35.976814 -295.916604)
		(size 0.4572)
		(drill 0.2032)
		(layers "F.Cu" "B.Cu")
		(net "GND")
	)
	(via
		(at 416.575494 -163.692078)
		(size 0.49022)
		(drill 0.254)
		(layers "F.Cu" "B.Cu")
		(net "GND")
	)
	(via
		(at 102.927658 -255.817624)
		(size 0.4572)
		(drill 0.2032)
		(layers "F.Cu" "B.Cu")
		(net "GND")
	)
	(via
		(at 13.345414 -249.166634)
		(size 0.4572)
		(drill 0.2032)
		(layers "F.Cu" "B.Cu")
		(net "GND")
	)
	(via
		(at 104.121966 -234.15625)
		(size 0.4572)
		(drill 0.2032)
		(layers "F.Cu" "B.Cu")
		(net "GND")
	)
	(via
		(at 382.135634 -214.546434)
		(size 0.4572)
		(drill 0.2032)
		(layers "F.Cu" "B.Cu")
		(net "GND")
	)
	(via
		(at 95.14586 -187.179712)
		(size 0.6604)
		(drill 0.3302)
		(layers "F.Cu" "B.Cu")
		(net "GND")
	)
	(via
		(at 202.971146 -229.616762)
		(size 0.4572)
		(drill 0.2032)
		(layers "F.Cu" "B.Cu")
		(net "GND")
	)
	(via
		(at 191.983614 -264.466578)
		(size 0.4572)
		(drill 0.2032)
		(layers "F.Cu" "B.Cu")
		(net "GND")
	)
	(via
		(at 373.43588 -36.921948)
		(size 0.508)
		(drill 0.254)
		(layers "F.Cu" "B.Cu")
		(net "GND")
	)
	(via
		(at 214.0204 -121.2088)
		(size 0.508)
		(drill 0.254)
		(layers "F.Cu" "B.Cu")
		(net "GND")
	)
	(via
		(at 467.535514 -170.04538)
		(size 0.508)
		(drill 0.254)
		(layers "F.Cu" "B.Cu")
		(net "GND")
	)
	(via
		(at 52.15128 -169.560748)
		(size 0.508)
		(drill 0.254)
		(layers "F.Cu" "B.Cu")
		(net "GND")
	)
	(via
		(at 296.794682 -314.616592)
		(size 0.4572)
		(drill 0.2032)
		(layers "F.Cu" "B.Cu")
		(net "GND")
	)
	(via
		(at 58.608214 -295.916604)
		(size 0.4572)
		(drill 0.2032)
		(layers "F.Cu" "B.Cu")
		(net "GND")
	)
	(via
		(at 334.205834 -222.761556)
		(size 0.4572)
		(drill 0.2032)
		(layers "F.Cu" "B.Cu")
		(net "GND")
	)
	(via
		(at 434.589682 -305.266598)
		(size 0.4572)
		(drill 0.2032)
		(layers "F.Cu" "B.Cu")
		(net "GND")
	)
	(via
		(at 98.123248 -279.150318)
		(size 0.4572)
		(drill 0.2032)
		(layers "F.Cu" "B.Cu")
		(net "GND")
	)
	(via
		(at 358.348026 -326.948292)
		(size 0.508)
		(drill 0.254)
		(layers "F.Cu" "B.Cu")
		(net "GND")
	)
	(via
		(at 197.637146 -231.316784)
		(size 0.4572)
		(drill 0.2032)
		(layers "F.Cu" "B.Cu")
		(net "GND")
	)
	(via
		(at 25.48509 -19.13636)
		(size 0.508)
		(drill 0.254)
		(layers "F.Cu" "B.Cu")
		(net "GND")
	)
	(via
		(at 301.93488 -14.41577)
		(size 0.508)
		(drill 0.254)
		(layers "F.Cu" "B.Cu")
		(net "GND")
	)
	(via
		(at 430.489614 -292.516814)
		(size 0.4572)
		(drill 0.2032)
		(layers "F.Cu" "B.Cu")
		(net "GND")
	)
	(via
		(at 178.286918 -188.68771)
		(size 0.508)
		(drill 0.254)
		(layers "F.Cu" "B.Cu")
		(net "GND")
	)
	(via
		(at 447.467482 -262.76681)
		(size 0.4572)
		(drill 0.2032)
		(layers "F.Cu" "B.Cu")
		(net "GND")
	)
	(via
		(at 169.352214 -284.866588)
		(size 0.4572)
		(drill 0.2032)
		(layers "F.Cu" "B.Cu")
		(net "GND")
	)
	(via
		(at 199.527414 -247.466612)
		(size 0.4572)
		(drill 0.2032)
		(layers "F.Cu" "B.Cu")
		(net "GND")
	)
	(via
		(at 22.123146 -270.416782)
		(size 0.4572)
		(drill 0.2032)
		(layers "F.Cu" "B.Cu")
		(net "GND")
	)
	(via
		(at 449.677282 -219.41663)
		(size 0.4572)
		(drill 0.2032)
		(layers "F.Cu" "B.Cu")
		(net "GND")
	)
	(via
		(at 33.767014 -299.316648)
		(size 0.4572)
		(drill 0.2032)
		(layers "F.Cu" "B.Cu")
		(net "GND")
	)
	(via
		(at 325.250048 -426.54728)
		(size 0.4572)
		(drill 0.2032)
		(layers "F.Cu" "B.Cu")
		(net "GND")
	)
	(via
		(at 4.412234 -12.544552)
		(size 0.508)
		(drill 0.254)
		(layers "F.Cu" "B.Cu")
		(net "GND")
	)
	(via
		(at 39.420546 -201.56678)
		(size 0.4572)
		(drill 0.2032)
		(layers "F.Cu" "B.Cu")
		(net "GND")
	)
	(via
		(at 340.250018 -429.147224)
		(size 0.4572)
		(drill 0.2032)
		(layers "F.Cu" "B.Cu")
		(net "GND")
	)
	(via
		(at 427.045882 -230.466646)
		(size 0.4572)
		(drill 0.2032)
		(layers "F.Cu" "B.Cu")
		(net "GND")
	)
	(via
		(at 199.527414 -278.916638)
		(size 0.4572)
		(drill 0.2032)
		(layers "F.Cu" "B.Cu")
		(net "GND")
	)
	(via
		(at 449.677282 -277.216616)
		(size 0.4572)
		(drill 0.2032)
		(layers "F.Cu" "B.Cu")
		(net "GND")
	)
	(via
		(at 347.363034 -216.25052)
		(size 0.4572)
		(drill 0.2032)
		(layers "F.Cu" "B.Cu")
		(net "GND")
	)
	(via
		(at 439.923682 -286.56661)
		(size 0.4572)
		(drill 0.2032)
		(layers "F.Cu" "B.Cu")
		(net "GND")
	)
	(via
		(at 216.824814 -278.916638)
		(size 0.4572)
		(drill 0.2032)
		(layers "F.Cu" "B.Cu")
		(net "GND")
	)
	(via
		(at 96.133412 -233.34218)
		(size 0.4572)
		(drill 0.2032)
		(layers "F.Cu" "B.Cu")
		(net "GND")
	)
	(via
		(at 9.245346 -216.016586)
		(size 0.4572)
		(drill 0.2032)
		(layers "F.Cu" "B.Cu")
		(net "GND")
	)
	(via
		(at 118.218966 -230.900478)
		(size 0.4572)
		(drill 0.2032)
		(layers "F.Cu" "B.Cu")
		(net "GND")
	)
	(via
		(at 308.10454 -404.51786)
		(size 0.4572)
		(drill 0.254)
		(layers "F.Cu" "B.Cu")
		(net "GND")
	)
	(via
		(at 153.68524 -10.770108)
		(size 0.508)
		(drill 0.254)
		(layers "F.Cu" "B.Cu")
		(net "GND")
	)
	(via
		(at 284.618176 -79.2988)
		(size 0.508)
		(drill 0.254)
		(layers "F.Cu" "B.Cu")
		(net "GND")
	)
	(via
		(at 135.245094 -255.547622)
		(size 0.4572)
		(drill 0.2032)
		(layers "F.Cu" "B.Cu")
		(net "GND")
	)
	(via
		(at 292.314122 -360.102404)
		(size 0.508)
		(drill 0.254)
		(layers "F.Cu" "B.Cu")
		(net "GND")
	)
	(via
		(at 88.255094 -273.453098)
		(size 0.4572)
		(drill 0.2032)
		(layers "F.Cu" "B.Cu")
		(net "GND")
	)
	(via
		(at 207.071214 -275.516594)
		(size 0.4572)
		(drill 0.2032)
		(layers "F.Cu" "B.Cu")
		(net "GND")
	)
	(via
		(at 104.76611 -354.045012)
		(size 0.508)
		(drill 0.254)
		(layers "F.Cu" "B.Cu")
		(net "GND")
	)
	(via
		(at 168.029636 -10.603992)
		(size 0.508)
		(drill 0.254)
		(layers "F.Cu" "B.Cu")
		(net "GND")
	)
	(via
		(at 378.956062 -287.28924)
		(size 0.4572)
		(drill 0.2032)
		(layers "F.Cu" "B.Cu")
		(net "GND")
	)
	(via
		(at 428.279814 -278.066754)
		(size 0.4572)
		(drill 0.2032)
		(layers "F.Cu" "B.Cu")
		(net "GND")
	)
	(via
		(at 14.579346 -251.716794)
		(size 0.4572)
		(drill 0.2032)
		(layers "F.Cu" "B.Cu")
		(net "GND")
	)
	(via
		(at 384.485134 -243.108988)
		(size 0.4318)
		(drill 0.2032)
		(layers "F.Cu" "B.Cu")
		(net "GND")
	)
	(via
		(at 453.121014 -220.266768)
		(size 0.4572)
		(drill 0.2032)
		(layers "F.Cu" "B.Cu")
		(net "GND")
	)
	(via
		(at 33.190688 -4.962652)
		(size 0.508)
		(drill 0.254)
		(layers "F.Cu" "B.Cu")
		(net "GND")
	)
	(via
		(at 419.76802 -235.566712)
		(size 0.4572)
		(drill 0.2032)
		(layers "F.Cu" "B.Cu")
		(net "GND")
	)
	(via
		(at 311.882282 -215.166702)
		(size 0.4572)
		(drill 0.2032)
		(layers "F.Cu" "B.Cu")
		(net "GND")
	)
	(via
		(at 430.489614 -287.416748)
		(size 0.4572)
		(drill 0.2032)
		(layers "F.Cu" "B.Cu")
		(net "GND")
	)
	(via
		(at 289.250882 -224.516696)
		(size 0.4572)
		(drill 0.2032)
		(layers "F.Cu" "B.Cu")
		(net "GND")
	)
	(via
		(at 162.481514 -403.883876)
		(size 0.4064)
		(drill 0.2032)
		(layers "F.Cu" "B.Cu")
		(net "GND")
	)
	(via
		(at 369.448334 -223.575626)
		(size 0.4572)
		(drill 0.2032)
		(layers "F.Cu" "B.Cu")
		(net "GND")
	)
	(via
		(at 151.349964 -436.347362)
		(size 0.4572)
		(drill 0.2032)
		(layers "F.Cu" "B.Cu")
		(net "GND")
	)
	(via
		(at 210.514946 -313.766708)
		(size 0.4572)
		(drill 0.2032)
		(layers "F.Cu" "B.Cu")
		(net "GND")
	)
	(via
		(at 134.305548 -265.314176)
		(size 0.4572)
		(drill 0.2032)
		(layers "F.Cu" "B.Cu")
		(net "GND")
	)
	(via
		(at 420.736014 -279.766776)
		(size 0.4572)
		(drill 0.2032)
		(layers "F.Cu" "B.Cu")
		(net "GND")
	)
	(via
		(at 130.493262 -410.664152)
		(size 0.4572)
		(drill 0.254)
		(layers "F.Cu" "B.Cu")
		(net "GND")
	)
	(via
		(at 195.427346 -261.916672)
		(size 0.4572)
		(drill 0.2032)
		(layers "F.Cu" "B.Cu")
		(net "GND")
	)
	(via
		(at 182.549546 -204.96657)
		(size 0.4572)
		(drill 0.2032)
		(layers "F.Cu" "B.Cu")
		(net "GND")
	)
	(via
		(at 375.557034 -248.806208)
		(size 0.4572)
		(drill 0.2032)
		(layers "F.Cu" "B.Cu")
		(net "GND")
	)
	(via
		(at 91.92641 -404.51786)
		(size 0.4572)
		(drill 0.254)
		(layers "F.Cu" "B.Cu")
		(net "GND")
	)
	(via
		(at 9.245346 -225.36658)
		(size 0.4572)
		(drill 0.2032)
		(layers "F.Cu" "B.Cu")
		(net "GND")
	)
	(via
		(at 268.829282 -222.816674)
		(size 0.4572)
		(drill 0.2032)
		(layers "F.Cu" "B.Cu")
		(net "GND")
	)
	(via
		(at 432.379882 -269.566644)
		(size 0.4572)
		(drill 0.2032)
		(layers "F.Cu" "B.Cu")
		(net "GND")
	)
	(via
		(at 407.858214 -248.31675)
		(size 0.4572)
		(drill 0.2032)
		(layers "F.Cu" "B.Cu")
		(net "GND")
	)
	(via
		(at 108.43387 -255.74625)
		(size 0.4572)
		(drill 0.2032)
		(layers "F.Cu" "B.Cu")
		(net "GND")
	)
	(via
		(at 111.640366 -226.017328)
		(size 0.4572)
		(drill 0.2032)
		(layers "F.Cu" "B.Cu")
		(net "GND")
	)
	(via
		(at 150.54834 -39.710868)
		(size 0.508)
		(drill 0.254)
		(layers "F.Cu" "B.Cu")
		(net "GND")
	)
	(via
		(at 276.373082 -275.516594)
		(size 0.4572)
		(drill 0.2032)
		(layers "F.Cu" "B.Cu")
		(net "GND")
	)
	(via
		(at 429.566832 -7.215124)
		(size 0.508)
		(drill 0.254)
		(layers "F.Cu" "B.Cu")
		(net "GND")
	)
	(via
		(at 346.423234 -219.506038)
		(size 0.4572)
		(drill 0.2032)
		(layers "F.Cu" "B.Cu")
		(net "GND")
	)
	(via
		(at 118.804944 -79.486252)
		(size 0.508)
		(drill 0.254)
		(layers "F.Cu" "B.Cu")
		(net "GND")
	)
	(via
		(at 205.180946 -267.016738)
		(size 0.4572)
		(drill 0.2032)
		(layers "F.Cu" "B.Cu")
		(net "GND")
	)
	(via
		(at 48.854614 -250.866656)
		(size 0.4572)
		(drill 0.2032)
		(layers "F.Cu" "B.Cu")
		(net "GND")
	)
	(via
		(at 40.533828 -5.596636)
		(size 0.508)
		(drill 0.254)
		(layers "F.Cu" "B.Cu")
		(net "GND")
	)
	(via
		(at 405.648414 -300.166786)
		(size 0.4572)
		(drill 0.2032)
		(layers "F.Cu" "B.Cu")
		(net "GND")
	)
	(via
		(at 262.519414 -201.56678)
		(size 0.4572)
		(drill 0.2032)
		(layers "F.Cu" "B.Cu")
		(net "GND")
	)
	(via
		(at 165.252146 -279.766776)
		(size 0.4572)
		(drill 0.2032)
		(layers "F.Cu" "B.Cu")
		(net "GND")
	)
	(via
		(at 296.146474 -354.870004)
		(size 0.508)
		(drill 0.254)
		(layers "F.Cu" "B.Cu")
		(net "GND")
	)
	(via
		(at 35.976814 -245.76659)
		(size 0.4572)
		(drill 0.2032)
		(layers "F.Cu" "B.Cu")
		(net "GND")
	)
	(via
		(at 445.05753 -70.284594)
		(size 0.508)
		(drill 0.254)
		(layers "F.Cu" "B.Cu")
		(net "GND")
	)
	(via
		(at 338.824316 -410.664152)
		(size 0.4572)
		(drill 0.254)
		(layers "F.Cu" "B.Cu")
		(net "GND")
	)
	(via
		(at 29.666946 -204.96657)
		(size 0.4572)
		(drill 0.2032)
		(layers "F.Cu" "B.Cu")
		(net "GND")
	)
	(via
		(at 450.911214 -210.916774)
		(size 0.4572)
		(drill 0.2032)
		(layers "F.Cu" "B.Cu")
		(net "GND")
	)
	(via
		(at 384.485134 -230.086662)
		(size 0.4572)
		(drill 0.2032)
		(layers "F.Cu" "B.Cu")
		(net "GND")
	)
	(via
		(at 413.652462 -407.638504)
		(size 0.4572)
		(drill 0.254)
		(layers "F.Cu" "B.Cu")
		(net "GND")
	)
	(via
		(at 16.789146 -220.266768)
		(size 0.4572)
		(drill 0.2032)
		(layers "F.Cu" "B.Cu")
		(net "GND")
	)
	(via
		(at 18.679414 -230.466646)
		(size 0.4572)
		(drill 0.2032)
		(layers "F.Cu" "B.Cu")
		(net "GND")
	)
	(via
		(at 403.6187 -6.586474)
		(size 0.508)
		(drill 0.254)
		(layers "F.Cu" "B.Cu")
		(net "GND")
	)
	(via
		(at 370.486686 -12.544552)
		(size 0.508)
		(drill 0.254)
		(layers "F.Cu" "B.Cu")
		(net "GND")
	)
	(via
		(at 371.32768 -234.970066)
		(size 0.4572)
		(drill 0.2032)
		(layers "F.Cu" "B.Cu")
		(net "GND")
	)
	(via
		(at 179.105814 -271.266666)
		(size 0.4572)
		(drill 0.2032)
		(layers "F.Cu" "B.Cu")
		(net "GND")
	)
	(via
		(at 417.292282 -258.516628)
		(size 0.4572)
		(drill 0.2032)
		(layers "F.Cu" "B.Cu")
		(net "GND")
	)
	(via
		(at 20.889214 -198.166736)
		(size 0.4572)
		(drill 0.2032)
		(layers "F.Cu" "B.Cu")
		(net "GND")
	)
	(via
		(at 402.046948 -12.37488)
		(size 0.508)
		(drill 0.254)
		(layers "F.Cu" "B.Cu")
		(net "GND")
	)
	(via
		(at 107.990894 -279.964134)
		(size 0.4572)
		(drill 0.2032)
		(layers "F.Cu" "B.Cu")
		(net "GND")
	)
	(via
		(at 13.345414 -316.316614)
		(size 0.4572)
		(drill 0.2032)
		(layers "F.Cu" "B.Cu")
		(net "GND")
	)
	(via
		(at 292.694614 -234.716574)
		(size 0.4572)
		(drill 0.2032)
		(layers "F.Cu" "B.Cu")
		(net "GND")
	)
	(via
		(at 447.467482 -211.766658)
		(size 0.4572)
		(drill 0.2032)
		(layers "F.Cu" "B.Cu")
		(net "GND")
	)
	(via
		(at 329.25004 -433.747164)
		(size 0.4572)
		(drill 0.2032)
		(layers "F.Cu" "B.Cu")
		(net "GND")
	)
	(via
		(at 41.310814 -295.916604)
		(size 0.4572)
		(drill 0.2032)
		(layers "F.Cu" "B.Cu")
		(net "GND")
	)
	(via
		(at 0.76454 -41.480232)
		(size 0.508)
		(drill 0.254)
		(layers "F.Cu" "B.Cu")
		(net "GND")
	)
	(via
		(at 88.145366 -229.272846)
		(size 0.4572)
		(drill 0.2032)
		(layers "F.Cu" "B.Cu")
		(net "GND")
	)
	(via
		(at 417.292282 -297.616626)
		(size 0.4572)
		(drill 0.2032)
		(layers "F.Cu" "B.Cu")
		(net "GND")
	)
	(via
		(at 388.349998 -430.147222)
		(size 0.4572)
		(drill 0.2032)
		(layers "F.Cu" "B.Cu")
		(net "GND")
	)
	(via
		(at 175.603154 -350.754188)
		(size 0.508)
		(drill 0.254)
		(layers "F.Cu" "B.Cu")
		(net "GND")
	)
	(via
		(at 98.336608 -401.995386)
		(size 0.508)
		(drill 0.254)
		(layers "F.Cu" "B.Cu")
		(net "GND")
	)
	(via
		(at 102.834694 -249.242326)
		(size 0.4572)
		(drill 0.2032)
		(layers "F.Cu" "B.Cu")
		(net "GND")
	)
	(via
		(at 268.829282 -282.316682)
		(size 0.4572)
		(drill 0.2032)
		(layers "F.Cu" "B.Cu")
		(net "GND")
	)
	(via
		(at 294.904414 -315.46673)
		(size 0.4572)
		(drill 0.2032)
		(layers "F.Cu" "B.Cu")
		(net "GND")
	)
	(via
		(at 43.520614 -316.316614)
		(size 0.4572)
		(drill 0.2032)
		(layers "F.Cu" "B.Cu")
		(net "GND")
	)
	(via
		(at 281.707082 -235.566712)
		(size 0.4572)
		(drill 0.2032)
		(layers "F.Cu" "B.Cu")
		(net "GND")
	)
	(via
		(at 381.665734 -226.831144)
		(size 0.4572)
		(drill 0.2032)
		(layers "F.Cu" "B.Cu")
		(net "GND")
	)
	(via
		(at 377.712732 -71.489824)
		(size 0.508)
		(drill 0.254)
		(layers "F.Cu" "B.Cu")
		(net "GND")
	)
	(via
		(at 382.135634 -235.783882)
		(size 0.4572)
		(drill 0.2032)
		(layers "F.Cu" "B.Cu")
		(net "GND")
	)
	(via
		(at 417.292282 -247.466612)
		(size 0.4572)
		(drill 0.2032)
		(layers "F.Cu" "B.Cu")
		(net "GND")
	)
	(via
		(at 311.882282 -261.066788)
		(size 0.4572)
		(drill 0.2032)
		(layers "F.Cu" "B.Cu")
		(net "GND")
	)
	(via
		(at 302.664114 -311.216802)
		(size 0.4572)
		(drill 0.2032)
		(layers "F.Cu" "B.Cu")
		(net "GND")
	)
	(via
		(at 88.78189 -12.544552)
		(size 0.508)
		(drill 0.254)
		(layers "F.Cu" "B.Cu")
		(net "GND")
	)
	(via
		(at 14.579346 -238.966756)
		(size 0.4572)
		(drill 0.2032)
		(layers "F.Cu" "B.Cu")
		(net "GND")
	)
	(via
		(at 390.863582 -404.51786)
		(size 0.4572)
		(drill 0.254)
		(layers "F.Cu" "B.Cu")
		(net "GND")
	)
	(via
		(at 58.608214 -239.94364)
		(size 0.4572)
		(drill 0.2032)
		(layers "F.Cu" "B.Cu")
		(net "GND")
	)
	(via
		(at 373.207534 -234.970066)
		(size 0.4572)
		(drill 0.2032)
		(layers "F.Cu" "B.Cu")
		(net "GND")
	)
	(via
		(at 449.677282 -215.166702)
		(size 0.4572)
		(drill 0.2032)
		(layers "F.Cu" "B.Cu")
		(net "GND")
	)
	(via
		(at 69.250052 -432.451256)
		(size 0.4572)
		(drill 0.2032)
		(layers "F.Cu" "B.Cu")
		(net "GND")
	)
	(via
		(at 279.092152 -323.429376)
		(size 0.4572)
		(drill 0.2032)
		(layers "F.Cu" "B.Cu")
		(net "GND")
	)
	(via
		(at 212.724746 -301.866808)
		(size 0.4572)
		(drill 0.2032)
		(layers "F.Cu" "B.Cu")
		(net "GND")
	)
	(via
		(at 28.638246 -391.310876)
		(size 0.508)
		(drill 0.254)
		(layers "F.Cu" "B.Cu")
		(net "GND")
	)
	(via
		(at 172.795946 -295.06672)
		(size 0.4572)
		(drill 0.2032)
		(layers "F.Cu" "B.Cu")
		(net "GND")
	)
	(via
		(at 24.332946 -258.516628)
		(size 0.4572)
		(drill 0.2032)
		(layers "F.Cu" "B.Cu")
		(net "GND")
	)
	(via
		(at 126.098554 -333.79283)
		(size 0.508)
		(drill 0.254)
		(layers "F.Cu" "B.Cu")
		(net "GND")
	)
	(via
		(at 121.618248 -274.266914)
		(size 0.4572)
		(drill 0.2032)
		(layers "F.Cu" "B.Cu")
		(net "GND")
	)
	(via
		(at 420.736014 -306.116736)
		(size 0.4572)
		(drill 0.2032)
		(layers "F.Cu" "B.Cu")
		(net "GND")
	)
	(via
		(at 99.865434 -331.08392)
		(size 0.508)
		(drill 0.254)
		(layers "F.Cu" "B.Cu")
		(net "GND")
	)
	(via
		(at 133.835648 -257.98907)
		(size 0.4572)
		(drill 0.2032)
		(layers "F.Cu" "B.Cu")
		(net "GND")
	)
	(via
		(at 143.36522 -11.463528)
		(size 0.508)
		(drill 0.254)
		(layers "F.Cu" "B.Cu")
		(net "GND")
	)
	(via
		(at 202.971146 -231.316784)
		(size 0.4572)
		(drill 0.2032)
		(layers "F.Cu" "B.Cu")
		(net "GND")
	)
	(via
		(at 460.664814 -273.816572)
		(size 0.4572)
		(drill 0.2032)
		(layers "F.Cu" "B.Cu")
		(net "GND")
	)
	(via
		(at 182.549546 -236.416596)
		(size 0.4572)
		(drill 0.2032)
		(layers "F.Cu" "B.Cu")
		(net "GND")
	)
	(via
		(at 266.619482 -284.866588)
		(size 0.4572)
		(drill 0.2032)
		(layers "F.Cu" "B.Cu")
		(net "GND")
	)
	(via
		(at 171.562014 -306.96662)
		(size 0.4572)
		(drill 0.2032)
		(layers "F.Cu" "B.Cu")
		(net "GND")
	)
	(via
		(at 183.22163 -418.4142)
		(size 0.508)
		(drill 0.254)
		(layers "F.Cu" "B.Cu")
		(net "GND")
	)
	(via
		(at 97.073466 -234.970066)
		(size 0.4572)
		(drill 0.2032)
		(layers "F.Cu" "B.Cu")
		(net "GND")
	)
	(via
		(at 86.845394 -256.361438)
		(size 0.4318)
		(drill 0.2032)
		(layers "F.Cu" "B.Cu")
		(net "GND")
	)
	(via
		(at 329.25004 -436.051198)
		(size 0.4572)
		(drill 0.2032)
		(layers "F.Cu" "B.Cu")
		(net "GND")
	)
	(via
		(at 115.869466 -217.064336)
		(size 0.4572)
		(drill 0.2032)
		(layers "F.Cu" "B.Cu")
		(net "GND")
	)
	(via
		(at 96.305878 -332.56601)
		(size 0.49022)
		(drill 0.254)
		(layers "F.Cu" "B.Cu")
		(net "GND")
	)
	(via
		(at 42.331894 -437.187594)
		(size 0.508)
		(drill 0.254)
		(layers "F.Cu" "B.Cu")
		(net "GND")
	)
	(via
		(at 18.679414 -272.966688)
		(size 0.4572)
		(drill 0.2032)
		(layers "F.Cu" "B.Cu")
		(net "GND")
	)
	(via
		(at 205.180946 -279.766776)
		(size 0.4572)
		(drill 0.2032)
		(layers "F.Cu" "B.Cu")
		(net "GND")
	)
	(via
		(at 102.821994 -284.033722)
		(size 0.4572)
		(drill 0.2032)
		(layers "F.Cu" "B.Cu")
		(net "GND")
	)
	(via
		(at 374.617234 -222.761556)
		(size 0.4572)
		(drill 0.2032)
		(layers "F.Cu" "B.Cu")
		(net "GND")
	)
	(via
		(at 350.9899 -400.224244)
		(size 0.4572)
		(drill 0.254)
		(layers "F.Cu" "B.Cu")
		(net "GND")
	)
	(via
		(at 8.38708 -97.236788)
		(size 0.508)
		(drill 0.254)
		(layers "F.Cu" "B.Cu")
		(net "GND")
	)
	(via
		(at 358.067864 -43.610784)
		(size 0.508)
		(drill 0.254)
		(layers "F.Cu" "B.Cu")
		(net "GND")
	)
	(via
		(at 178.289204 -43.800014)
		(size 0.508)
		(drill 0.254)
		(layers "F.Cu" "B.Cu")
		(net "GND")
	)
	(via
		(at 56.182514 -291.666676)
		(size 0.4572)
		(drill 0.2032)
		(layers "F.Cu" "B.Cu")
		(net "GND")
	)
	(via
		(at 39.420546 -199.01662)
		(size 0.4572)
		(drill 0.2032)
		(layers "F.Cu" "B.Cu")
		(net "GND")
	)
	(via
		(at 314.092082 -262.76681)
		(size 0.4572)
		(drill 0.2032)
		(layers "F.Cu" "B.Cu")
		(net "GND")
	)
	(via
		(at 205.180946 -240.666778)
		(size 0.4572)
		(drill 0.2032)
		(layers "F.Cu" "B.Cu")
		(net "GND")
	)
	(via
		(at 9.245346 -212.616796)
		(size 0.4572)
		(drill 0.2032)
		(layers "F.Cu" "B.Cu")
		(net "GND")
	)
	(via
		(at 268.829282 -301.01667)
		(size 0.4572)
		(drill 0.2032)
		(layers "F.Cu" "B.Cu")
		(net "GND")
	)
	(via
		(at 126.677166 -216.25052)
		(size 0.4572)
		(drill 0.2032)
		(layers "F.Cu" "B.Cu")
		(net "GND")
	)
	(via
		(at 427.045882 -316.316614)
		(size 0.4572)
		(drill 0.2032)
		(layers "F.Cu" "B.Cu")
		(net "GND")
	)
	(via
		(at 354.411534 -217.064336)
		(size 0.4572)
		(drill 0.2032)
		(layers "F.Cu" "B.Cu")
		(net "GND")
	)
	(via
		(at 418.356796 -10.16508)
		(size 0.508)
		(drill 0.254)
		(layers "F.Cu" "B.Cu")
		(net "GND")
	)
	(via
		(at 287.360614 -311.216802)
		(size 0.4572)
		(drill 0.2032)
		(layers "F.Cu" "B.Cu")
		(net "GND")
	)
	(via
		(at 262.519414 -306.116736)
		(size 0.4572)
		(drill 0.2032)
		(layers "F.Cu" "B.Cu")
		(net "GND")
	)
	(via
		(at 385.064762 -281.59202)
		(size 0.4572)
		(drill 0.2032)
		(layers "F.Cu" "B.Cu")
		(net "GND")
	)
	(via
		(at 65.721484 -103.591868)
		(size 0.508)
		(drill 0.254)
		(layers "F.Cu" "B.Cu")
		(net "GND")
	)
	(via
		(at 424.836082 -205.816708)
		(size 0.4572)
		(drill 0.2032)
		(layers "F.Cu" "B.Cu")
		(net "GND")
	)
	(via
		(at 31.876746 -244.916706)
		(size 0.4572)
		(drill 0.2032)
		(layers "F.Cu" "B.Cu")
		(net "GND")
	)
	(via
		(at 115.219734 -91.199462)
		(size 0.508)
		(drill 0.254)
		(layers "F.Cu" "B.Cu")
		(net "GND")
	)
	(via
		(at 127.726948 -279.964134)
		(size 0.4572)
		(drill 0.2032)
		(layers "F.Cu" "B.Cu")
		(net "GND")
	)
	(via
		(at 92.014294 -260.430772)
		(size 0.4572)
		(drill 0.2032)
		(layers "F.Cu" "B.Cu")
		(net "GND")
	)
	(via
		(at 37.210746 -220.266768)
		(size 0.4572)
		(drill 0.2032)
		(layers "F.Cu" "B.Cu")
		(net "GND")
	)
	(via
		(at 129.026666 -217.064336)
		(size 0.4572)
		(drill 0.2032)
		(layers "F.Cu" "B.Cu")
		(net "GND")
	)
	(via
		(at 320.718688 -403.883876)
		(size 0.4064)
		(drill 0.2032)
		(layers "F.Cu" "B.Cu")
		(net "GND")
	)
	(via
		(at 51.064414 -198.166736)
		(size 0.4572)
		(drill 0.2032)
		(layers "F.Cu" "B.Cu")
		(net "GND")
	)
	(via
		(at 405.648414 -279.766776)
		(size 0.4572)
		(drill 0.2032)
		(layers "F.Cu" "B.Cu")
		(net "GND")
	)
	(via
		(at 314.23102 -401.492212)
		(size 0.4572)
		(drill 0.254)
		(layers "F.Cu" "B.Cu")
		(net "GND")
	)
	(via
		(at 334.744822 -65.395348)
		(size 0.508)
		(drill 0.254)
		(layers "F.Cu" "B.Cu")
		(net "GND")
	)
	(via
		(at 59.250072 -426.69968)
		(size 0.4572)
		(drill 0.2032)
		(layers "F.Cu" "B.Cu")
		(net "GND")
	)
	(via
		(at 456.123802 -78.402434)
		(size 0.508)
		(drill 0.254)
		(layers "F.Cu" "B.Cu")
		(net "GND")
	)
	(via
		(at 164.018214 -230.466646)
		(size 0.4572)
		(drill 0.2032)
		(layers "F.Cu" "B.Cu")
		(net "GND")
	)
	(via
		(at 342.774016 -262.058658)
		(size 0.4572)
		(drill 0.2032)
		(layers "F.Cu" "B.Cu")
		(net "GND")
	)
	(via
		(at 419.502082 -301.01667)
		(size 0.4572)
		(drill 0.2032)
		(layers "F.Cu" "B.Cu")
		(net "GND")
	)
	(via
		(at 455.011282 -264.466578)
		(size 0.4572)
		(drill 0.2032)
		(layers "F.Cu" "B.Cu")
		(net "GND")
	)
	(via
		(at 45.093128 -350.874838)
		(size 0.508)
		(drill 0.254)
		(layers "F.Cu" "B.Cu")
		(net "GND")
	)
	(via
		(at 20.889214 -297.616626)
		(size 0.4572)
		(drill 0.2032)
		(layers "F.Cu" "B.Cu")
		(net "GND")
	)
	(via
		(at 254.635 -67.782948)
		(size 0.508)
		(drill 0.254)
		(layers "F.Cu" "B.Cu")
		(net "GND")
	)
	(via
		(at 407.858214 -298.466764)
		(size 0.4572)
		(drill 0.2032)
		(layers "F.Cu" "B.Cu")
		(net "GND")
	)
	(via
		(at 207.071214 -282.316682)
		(size 0.4572)
		(drill 0.2032)
		(layers "F.Cu" "B.Cu")
		(net "GND")
	)
	(via
		(at 367.678716 -287.28924)
		(size 0.4572)
		(drill 0.2032)
		(layers "F.Cu" "B.Cu")
		(net "GND")
	)
	(via
		(at 11.135614 -204.116686)
		(size 0.4572)
		(drill 0.2032)
		(layers "F.Cu" "B.Cu")
		(net "GND")
	)
	(via
		(at 299.004482 -303.566576)
		(size 0.4572)
		(drill 0.2032)
		(layers "F.Cu" "B.Cu")
		(net "GND")
	)
	(via
		(at 132.895594 -261.244842)
		(size 0.4572)
		(drill 0.2032)
		(layers "F.Cu" "B.Cu")
		(net "GND")
	)
	(via
		(at 257.683 -68.544948)
		(size 0.508)
		(drill 0.254)
		(layers "F.Cu" "B.Cu")
		(net "GND")
	)
	(via
		(at 55.066946 -12.37488)
		(size 0.508)
		(drill 0.254)
		(layers "F.Cu" "B.Cu")
		(net "GND")
	)
	(via
		(at 314.307982 -282.316682)
		(size 0.4572)
		(drill 0.2032)
		(layers "F.Cu" "B.Cu")
		(net "GND")
	)
	(via
		(at 135.24484 -279.964134)
		(size 0.4572)
		(drill 0.2032)
		(layers "F.Cu" "B.Cu")
		(net "GND")
	)
	(via
		(at 266.619482 -286.56661)
		(size 0.4572)
		(drill 0.2032)
		(layers "F.Cu" "B.Cu")
		(net "GND")
	)
	(via
		(at 32.310324 -121.974864)
		(size 0.508)
		(drill 0.254)
		(layers "F.Cu" "B.Cu")
		(net "GND")
	)
	(via
		(at 125.847348 -284.847538)
		(size 0.4572)
		(drill 0.2032)
		(layers "F.Cu" "B.Cu")
		(net "GND")
	)
	(via
		(at 373.677434 -219.506038)
		(size 0.4572)
		(drill 0.2032)
		(layers "F.Cu" "B.Cu")
		(net "GND")
	)
	(via
		(at 132.425694 -271.825212)
		(size 0.4572)
		(drill 0.2032)
		(layers "F.Cu" "B.Cu")
		(net "GND")
	)
	(via
		(at 445.577214 -290.816792)
		(size 0.4572)
		(drill 0.2032)
		(layers "F.Cu" "B.Cu")
		(net "GND")
	)
	(via
		(at 405.648414 -290.816792)
		(size 0.4572)
		(drill 0.2032)
		(layers "F.Cu" "B.Cu")
		(net "GND")
	)
	(via
		(at 460.664814 -216.016586)
		(size 0.4572)
		(drill 0.2032)
		(layers "F.Cu" "B.Cu")
		(net "GND")
	)
	(via
		(at 349.24238 -234.15625)
		(size 0.4572)
		(drill 0.2032)
		(layers "F.Cu" "B.Cu")
		(net "GND")
	)
	(via
		(at 145.349976 -427.699678)
		(size 0.4572)
		(drill 0.2032)
		(layers "F.Cu" "B.Cu")
		(net "GND")
	)
	(via
		(at 457.221082 -308.666642)
		(size 0.4572)
		(drill 0.2032)
		(layers "F.Cu" "B.Cu")
		(net "GND")
	)
	(via
		(at 90.024966 -219.506038)
		(size 0.4572)
		(drill 0.2032)
		(layers "F.Cu" "B.Cu")
		(net "GND")
	)
	(via
		(at 335.632044 -81.239614)
		(size 0.508)
		(drill 0.254)
		(layers "F.Cu" "B.Cu")
		(net "GND")
	)
	(via
		(at 442.133482 -202.416664)
		(size 0.4572)
		(drill 0.2032)
		(layers "F.Cu" "B.Cu")
		(net "GND")
	)
	(via
		(at 39.420546 -276.366732)
		(size 0.4572)
		(drill 0.2032)
		(layers "F.Cu" "B.Cu")
		(net "GND")
	)
	(via
		(at 348.584774 -168.002712)
		(size 0.508)
		(drill 0.254)
		(layers "F.Cu" "B.Cu")
		(net "GND")
	)
	(via
		(at 107.991148 -276.708616)
		(size 0.4572)
		(drill 0.2032)
		(layers "F.Cu" "B.Cu")
		(net "GND")
	)
	(via
		(at 180.339746 -223.666558)
		(size 0.4572)
		(drill 0.2032)
		(layers "F.Cu" "B.Cu")
		(net "GND")
	)
	(via
		(at 246.753634 -61.558932)
		(size 0.508)
		(drill 0.254)
		(layers "F.Cu" "B.Cu")
		(net "GND")
	)
	(via
		(at 89.554812 -244.73662)
		(size 0.4572)
		(drill 0.2032)
		(layers "F.Cu" "B.Cu")
		(net "GND")
	)
	(via
		(at 99.422966 -219.506038)
		(size 0.4572)
		(drill 0.2032)
		(layers "F.Cu" "B.Cu")
		(net "GND")
	)
	(via
		(at 84.250022 -436.347362)
		(size 0.4572)
		(drill 0.2032)
		(layers "F.Cu" "B.Cu")
		(net "GND")
	)
	(via
		(at 417.292282 -249.166634)
		(size 0.4572)
		(drill 0.2032)
		(layers "F.Cu" "B.Cu")
		(net "GND")
	)
	(via
		(at 458.455014 -272.116804)
		(size 0.4572)
		(drill 0.2032)
		(layers "F.Cu" "B.Cu")
		(net "GND")
	)
	(via
		(at 257.185414 -298.466764)
		(size 0.4572)
		(drill 0.2032)
		(layers "F.Cu" "B.Cu")
		(net "GND")
	)
	(via
		(at 130.132074 -410.030168)
		(size 0.4064)
		(drill 0.2032)
		(layers "F.Cu" "B.Cu")
		(net "GND")
	)
	(via
		(at 268.829282 -280.61666)
		(size 0.4572)
		(drill 0.2032)
		(layers "F.Cu" "B.Cu")
		(net "GND")
	)
	(via
		(at 412.015686 -182.999126)
		(size 0.508)
		(drill 0.254)
		(layers "F.Cu" "B.Cu")
		(net "GND")
	)
	(via
		(at 102.869492 -260.812534)
		(size 0.4572)
		(drill 0.2032)
		(layers "F.Cu" "B.Cu")
		(net "GND")
	)
	(via
		(at 197.637146 -216.016586)
		(size 0.4572)
		(drill 0.2032)
		(layers "F.Cu" "B.Cu")
		(net "GND")
	)
	(via
		(at 332.905862 -264.50036)
		(size 0.4572)
		(drill 0.2032)
		(layers "F.Cu" "B.Cu")
		(net "GND")
	)
	(via
		(at 13.345414 -258.516628)
		(size 0.4572)
		(drill 0.2032)
		(layers "F.Cu" "B.Cu")
		(net "GND")
	)
	(via
		(at 180.339746 -216.016586)
		(size 0.4572)
		(drill 0.2032)
		(layers "F.Cu" "B.Cu")
		(net "GND")
	)
	(via
		(at 420.736014 -311.216802)
		(size 0.4572)
		(drill 0.2032)
		(layers "F.Cu" "B.Cu")
		(net "GND")
	)
	(via
		(at 310.207914 -238.966756)
		(size 0.4572)
		(drill 0.2032)
		(layers "F.Cu" "B.Cu")
		(net "GND")
	)
	(via
		(at 110.230666 -238.225838)
		(size 0.4572)
		(drill 0.2032)
		(layers "F.Cu" "B.Cu")
		(net "GND")
	)
	(via
		(at 216.824814 -266.1666)
		(size 0.4572)
		(drill 0.2032)
		(layers "F.Cu" "B.Cu")
		(net "GND")
	)
	(via
		(at 107.94492 -111.623348)
		(size 0.508)
		(drill 0.254)
		(layers "F.Cu" "B.Cu")
		(net "GND")
	)
	(via
		(at 35.976814 -289.966654)
		(size 0.4572)
		(drill 0.2032)
		(layers "F.Cu" "B.Cu")
		(net "GND")
	)
	(via
		(at 346.250006 -431.29962)
		(size 0.4572)
		(drill 0.2032)
		(layers "F.Cu" "B.Cu")
		(net "GND")
	)
	(via
		(at 277.607014 -197.316598)
		(size 0.4572)
		(drill 0.2032)
		(layers "F.Cu" "B.Cu")
		(net "GND")
	)
	(via
		(at 175.4124 -95.367348)
		(size 0.508)
		(drill 0.254)
		(layers "F.Cu" "B.Cu")
		(net "GND")
	)
	(via
		(at 308.191916 -410.664152)
		(size 0.4572)
		(drill 0.254)
		(layers "F.Cu" "B.Cu")
		(net "GND")
	)
	(via
		(at 20.889214 -308.666642)
		(size 0.4572)
		(drill 0.2032)
		(layers "F.Cu" "B.Cu")
		(net "GND")
	)
	(via
		(at 438.033414 -251.716794)
		(size 0.4572)
		(drill 0.2032)
		(layers "F.Cu" "B.Cu")
		(net "GND")
	)
	(via
		(at 259.075682 -228.766624)
		(size 0.4572)
		(drill 0.2032)
		(layers "F.Cu" "B.Cu")
		(net "GND")
	)
	(via
		(at 449.677282 -207.51673)
		(size 0.4572)
		(drill 0.2032)
		(layers "F.Cu" "B.Cu")
		(net "GND")
	)
	(via
		(at 87.675466 -221.94774)
		(size 0.4572)
		(drill 0.2032)
		(layers "F.Cu" "B.Cu")
		(net "GND")
	)
	(via
		(at 390.950958 -409.396184)
		(size 0.4572)
		(drill 0.254)
		(layers "F.Cu" "B.Cu")
		(net "GND")
	)
	(via
		(at 43.520614 -222.816674)
		(size 0.4572)
		(drill 0.2032)
		(layers "F.Cu" "B.Cu")
		(net "GND")
	)
	(via
		(at 302.448214 -265.316716)
		(size 0.4572)
		(drill 0.2032)
		(layers "F.Cu" "B.Cu")
		(net "GND")
	)
	(via
		(at 209.281014 -299.316648)
		(size 0.4572)
		(drill 0.2032)
		(layers "F.Cu" "B.Cu")
		(net "GND")
	)
	(via
		(at 365.888778 -330.25842)
		(size 0.508)
		(drill 0.254)
		(layers "F.Cu" "B.Cu")
		(net "GND")
	)
	(via
		(at 445.577214 -263.616694)
		(size 0.4572)
		(drill 0.2032)
		(layers "F.Cu" "B.Cu")
		(net "GND")
	)
	(via
		(at 348.412816 -270.19758)
		(size 0.4572)
		(drill 0.2032)
		(layers "F.Cu" "B.Cu")
		(net "GND")
	)
	(via
		(at 394.014198 -409.396184)
		(size 0.4572)
		(drill 0.254)
		(layers "F.Cu" "B.Cu")
		(net "GND")
	)
	(via
		(at 101.302312 -239.0394)
		(size 0.4572)
		(drill 0.2032)
		(layers "F.Cu" "B.Cu")
		(net "GND")
	)
	(via
		(at 344.07348 -236.597952)
		(size 0.4572)
		(drill 0.2032)
		(layers "F.Cu" "B.Cu")
		(net "GND")
	)
	(via
		(at 179.35575 -106.975402)
		(size 0.4572)
		(drill 0.254)
		(layers "F.Cu" "B.Cu")
		(net "GND")
	)
	(via
		(at 67.781678 -400.858228)
		(size 0.4064)
		(drill 0.2032)
		(layers "F.Cu" "B.Cu")
		(net "GND")
	)
	(via
		(at 373.677434 -239.0394)
		(size 0.4572)
		(drill 0.2032)
		(layers "F.Cu" "B.Cu")
		(net "GND")
	)
	(via
		(at 378.016262 -272.639282)
		(size 0.4572)
		(drill 0.2032)
		(layers "F.Cu" "B.Cu")
		(net "GND")
	)
	(via
		(at 348.465648 -331.08392)
		(size 0.508)
		(drill 0.254)
		(layers "F.Cu" "B.Cu")
		(net "GND")
	)
	(via
		(at 434.589682 -294.216582)
		(size 0.4572)
		(drill 0.2032)
		(layers "F.Cu" "B.Cu")
		(net "GND")
	)
	(via
		(at 361.460034 -247.178322)
		(size 0.4572)
		(drill 0.2032)
		(layers "F.Cu" "B.Cu")
		(net "GND")
	)
	(via
		(at 172.795946 -268.71676)
		(size 0.4572)
		(drill 0.2032)
		(layers "F.Cu" "B.Cu")
		(net "GND")
	)
	(via
		(at 432.379882 -284.866588)
		(size 0.4572)
		(drill 0.2032)
		(layers "F.Cu" "B.Cu")
		(net "GND")
	)
	(via
		(at 321.7037 -407.638504)
		(size 0.4572)
		(drill 0.254)
		(layers "F.Cu" "B.Cu")
		(net "GND")
	)
	(via
		(at 354.411534 -50.207672)
		(size 0.49022)
		(drill 0.254)
		(layers "F.Cu" "B.Cu")
		(net "GND")
	)
	(via
		(at 125.377448 -262.872474)
		(size 0.4572)
		(drill 0.2032)
		(layers "F.Cu" "B.Cu")
		(net "GND")
	)
	(via
		(at 33.767014 -269.566644)
		(size 0.4572)
		(drill 0.2032)
		(layers "F.Cu" "B.Cu")
		(net "GND")
	)
	(via
		(at 334.25003 -436.051198)
		(size 0.4572)
		(drill 0.2032)
		(layers "F.Cu" "B.Cu")
		(net "GND")
	)
	(via
		(at 136.075166 -229.272846)
		(size 0.4572)
		(drill 0.2032)
		(layers "F.Cu" "B.Cu")
		(net "GND")
	)
	(via
		(at 35.32632 -439.775092)
		(size 0.508)
		(drill 0.254)
		(layers "F.Cu" "B.Cu")
		(net "GND")
	)
	(via
		(at 143.020034 -400.858228)
		(size 0.4064)
		(drill 0.2032)
		(layers "F.Cu" "B.Cu")
		(net "GND")
	)
	(via
		(at 348.302834 -216.25052)
		(size 0.4572)
		(drill 0.2032)
		(layers "F.Cu" "B.Cu")
		(net "GND")
	)
	(via
		(at 432.085496 -110.1471)
		(size 0.508)
		(drill 0.254)
		(layers "F.Cu" "B.Cu")
		(net "GND")
	)
	(via
		(at 407.984198 -400.224244)
		(size 0.4572)
		(drill 0.254)
		(layers "F.Cu" "B.Cu")
		(net "GND")
	)
	(via
		(at 126.677166 -237.411514)
		(size 0.4572)
		(drill 0.2032)
		(layers "F.Cu" "B.Cu")
		(net "GND")
	)
	(via
		(at 234.15752 -388.01294)
		(size 0.508)
		(drill 0.254)
		(layers "F.Cu" "B.Cu")
		(net "GND")
	)
	(via
		(at 399.349976 -426.69968)
		(size 0.4572)
		(drill 0.2032)
		(layers "F.Cu" "B.Cu")
		(net "GND")
	)
	(via
		(at 329.25004 -428.851314)
		(size 0.4572)
		(drill 0.2032)
		(layers "F.Cu" "B.Cu")
		(net "GND")
	)
	(via
		(at 7.035546 -279.766776)
		(size 0.4572)
		(drill 0.2032)
		(layers "F.Cu" "B.Cu")
		(net "GND")
	)
	(via
		(at 51.039014 -345.64066)
		(size 0.508)
		(drill 0.254)
		(layers "F.Cu" "B.Cu")
		(net "GND")
	)
	(via
		(at 159.918146 -290.816792)
		(size 0.4572)
		(drill 0.2032)
		(layers "F.Cu" "B.Cu")
		(net "GND")
	)
	(via
		(at 294.904414 -278.066754)
		(size 0.4572)
		(drill 0.2032)
		(layers "F.Cu" "B.Cu")
		(net "GND")
	)
	(via
		(at 135.245348 -265.314176)
		(size 0.4572)
		(drill 0.2032)
		(layers "F.Cu" "B.Cu")
		(net "GND")
	)
	(via
		(at 356.373684 -244.763036)
		(size 0.4572)
		(drill 0.2032)
		(layers "F.Cu" "B.Cu")
		(net "GND")
	)
	(via
		(at 356.373684 -259.578348)
		(size 0.4572)
		(drill 0.2032)
		(layers "F.Cu" "B.Cu")
		(net "GND")
	)
	(via
		(at 153.194766 -406.370536)
		(size 0.4572)
		(drill 0.254)
		(layers "F.Cu" "B.Cu")
		(net "GND")
	)
	(via
		(at 341.918798 -43.751246)
		(size 0.4572)
		(drill 0.2032)
		(layers "F.Cu" "B.Cu")
		(net "GND")
	)
	(via
		(at 72.288146 -404.51786)
		(size 0.4572)
		(drill 0.254)
		(layers "F.Cu" "B.Cu")
		(net "GND")
	)
	(via
		(at 24.332946 -272.116804)
		(size 0.4572)
		(drill 0.2032)
		(layers "F.Cu" "B.Cu")
		(net "GND")
	)
	(via
		(at 68.340732 -0.76454)
		(size 0.508)
		(drill 0.254)
		(layers "F.Cu" "B.Cu")
		(net "GND")
	)
	(via
		(at 447.467482 -291.666676)
		(size 0.4572)
		(drill 0.2032)
		(layers "F.Cu" "B.Cu")
		(net "GND")
	)
	(via
		(at 120.942354 -410.030168)
		(size 0.4064)
		(drill 0.2032)
		(layers "F.Cu" "B.Cu")
		(net "GND")
	)
	(via
		(at 24.332946 -261.916672)
		(size 0.4572)
		(drill 0.2032)
		(layers "F.Cu" "B.Cu")
		(net "GND")
	)
	(via
		(at 422.945814 -258.516628)
		(size 0.4572)
		(drill 0.2032)
		(layers "F.Cu" "B.Cu")
		(net "GND")
	)
	(via
		(at 212.724746 -309.51678)
		(size 0.4572)
		(drill 0.2032)
		(layers "F.Cu" "B.Cu")
		(net "GND")
	)
	(via
		(at 165.447726 -409.396184)
		(size 0.4572)
		(drill 0.254)
		(layers "F.Cu" "B.Cu")
		(net "GND")
	)
	(via
		(at 97.543112 -240.667286)
		(size 0.4572)
		(drill 0.2032)
		(layers "F.Cu" "B.Cu")
		(net "GND")
	)
	(via
		(at 277.607014 -261.916672)
		(size 0.4572)
		(drill 0.2032)
		(layers "F.Cu" "B.Cu")
		(net "GND")
	)
	(via
		(at 416.575494 -172.328078)
		(size 0.49022)
		(drill 0.254)
		(layers "F.Cu" "B.Cu")
		(net "GND")
	)
	(via
		(at 335.399888 -407.00452)
		(size 0.4064)
		(drill 0.2032)
		(layers "F.Cu" "B.Cu")
		(net "GND")
	)
	(via
		(at 76.054458 -195.13931)
		(size 0.508)
		(drill 0.254)
		(layers "F.Cu" "B.Cu")
		(net "GND")
	)
	(via
		(at 194.193414 -198.166736)
		(size 0.4572)
		(drill 0.2032)
		(layers "F.Cu" "B.Cu")
		(net "GND")
	)
	(via
		(at 190.093346 -248.31675)
		(size 0.4572)
		(drill 0.2032)
		(layers "F.Cu" "B.Cu")
		(net "GND")
	)
	(via
		(at 178.222148 -352.074988)
		(size 0.508)
		(drill 0.254)
		(layers "F.Cu" "B.Cu")
		(net "GND")
	)
	(via
		(at 449.264278 -96.646492)
		(size 0.508)
		(drill 0.254)
		(layers "F.Cu" "B.Cu")
		(net "GND")
	)
	(via
		(at 333.845662 -257.98907)
		(size 0.4572)
		(drill 0.2032)
		(layers "F.Cu" "B.Cu")
		(net "GND")
	)
	(via
		(at 194.193414 -288.266632)
		(size 0.4572)
		(drill 0.2032)
		(layers "F.Cu" "B.Cu")
		(net "GND")
	)
	(via
		(at 304.552858 -149.533356)
		(size 0.508)
		(drill 0.254)
		(layers "F.Cu" "B.Cu")
		(net "GND")
	)
	(via
		(at 368.618262 -274.266914)
		(size 0.4572)
		(drill 0.2032)
		(layers "F.Cu" "B.Cu")
		(net "GND")
	)
	(via
		(at 89.664794 -269.38351)
		(size 0.4572)
		(drill 0.2032)
		(layers "F.Cu" "B.Cu")
		(net "GND")
	)
	(via
		(at 117.823996 -246.66956)
		(size 0.4572)
		(drill 0.2032)
		(layers "F.Cu" "B.Cu")
		(net "GND")
	)
	(via
		(at 407.858214 -279.766776)
		(size 0.4572)
		(drill 0.2032)
		(layers "F.Cu" "B.Cu")
		(net "GND")
	)
	(via
		(at 266.619482 -239.81664)
		(size 0.4572)
		(drill 0.2032)
		(layers "F.Cu" "B.Cu")
		(net "GND")
	)
	(via
		(at 350.835722 -252.214634)
		(size 0.4572)
		(drill 0.2032)
		(layers "F.Cu" "B.Cu")
		(net "GND")
	)
	(via
		(at 61.205364 -323.378322)
		(size 0.4572)
		(drill 0.2032)
		(layers "F.Cu" "B.Cu")
		(net "GND")
	)
	(via
		(at 53.434996 -353.195128)
		(size 0.49022)
		(drill 0.254)
		(layers "F.Cu" "B.Cu")
		(net "GND")
	)
	(via
		(at 366.268762 -265.314176)
		(size 0.4572)
		(drill 0.2032)
		(layers "F.Cu" "B.Cu")
		(net "GND")
	)
	(via
		(at 125.377194 -282.405836)
		(size 0.4572)
		(drill 0.2032)
		(layers "F.Cu" "B.Cu")
		(net "GND")
	)
	(via
		(at 345.15171 -55.355236)
		(size 0.4572)
		(drill 0.2032)
		(layers "F.Cu" "B.Cu")
		(net "GND")
	)
	(via
		(at 331.484224 -338.303616)
		(size 0.508)
		(drill 0.254)
		(layers "F.Cu" "B.Cu")
		(net "GND")
	)
	(via
		(at 129.606548 -262.058658)
		(size 0.4572)
		(drill 0.2032)
		(layers "F.Cu" "B.Cu")
		(net "GND")
	)
	(via
		(at 293.757096 -360.173524)
		(size 0.508)
		(drill 0.254)
		(layers "F.Cu" "B.Cu")
		(net "GND")
	)
	(via
		(at 101.302312 -243.922804)
		(size 0.4572)
		(drill 0.2032)
		(layers "F.Cu" "B.Cu")
		(net "GND")
	)
	(via
		(at 91.889326 -330.202032)
		(size 0.508)
		(drill 0.254)
		(layers "F.Cu" "B.Cu")
		(net "GND")
	)
	(via
		(at 339.484716 -269.38351)
		(size 0.4572)
		(drill 0.2032)
		(layers "F.Cu" "B.Cu")
		(net "GND")
	)
	(via
		(at 430.489614 -201.56678)
		(size 0.4572)
		(drill 0.2032)
		(layers "F.Cu" "B.Cu")
		(net "GND")
	)
	(via
		(at 188.35116 -354.73259)
		(size 0.508)
		(drill 0.254)
		(layers "F.Cu" "B.Cu")
		(net "GND")
	)
	(via
		(at 22.123146 -195.616576)
		(size 0.4572)
		(drill 0.2032)
		(layers "F.Cu" "B.Cu")
		(net "GND")
	)
	(via
		(at 186.649614 -316.316614)
		(size 0.4572)
		(drill 0.2032)
		(layers "F.Cu" "B.Cu")
		(net "GND")
	)
	(via
		(at 87.850726 -48.949864)
		(size 0.508)
		(drill 0.254)
		(layers "F.Cu" "B.Cu")
		(net "GND")
	)
	(via
		(at 367.098834 -226.017328)
		(size 0.4572)
		(drill 0.2032)
		(layers "F.Cu" "B.Cu")
		(net "GND")
	)
	(via
		(at 150.93696 -130.036062)
		(size 0.508)
		(drill 0.254)
		(layers "F.Cu" "B.Cu")
		(net "GND")
	)
	(via
		(at 458.455014 -244.916706)
		(size 0.4572)
		(drill 0.2032)
		(layers "F.Cu" "B.Cu")
		(net "GND")
	)
	(via
		(at 453.121014 -285.716726)
		(size 0.4572)
		(drill 0.2032)
		(layers "F.Cu" "B.Cu")
		(net "GND")
	)
	(via
		(at 186.649614 -239.81664)
		(size 0.4572)
		(drill 0.2032)
		(layers "F.Cu" "B.Cu")
		(net "GND")
	)
	(via
		(at 165.252146 -240.666778)
		(size 0.4572)
		(drill 0.2032)
		(layers "F.Cu" "B.Cu")
		(net "GND")
	)
	(via
		(at 310.82488 -52.288948)
		(size 0.508)
		(drill 0.254)
		(layers "F.Cu" "B.Cu")
		(net "GND")
	)
	(via
		(at 367.912904 -335.704434)
		(size 0.49022)
		(drill 0.254)
		(layers "F.Cu" "B.Cu")
		(net "GND")
	)
	(via
		(at 195.427346 -195.616576)
		(size 0.4572)
		(drill 0.2032)
		(layers "F.Cu" "B.Cu")
		(net "GND")
	)
	(via
		(at 343.133934 -223.575626)
		(size 0.4572)
		(drill 0.2032)
		(layers "F.Cu" "B.Cu")
		(net "GND")
	)
	(via
		(at 424.836082 -316.316614)
		(size 0.4572)
		(drill 0.2032)
		(layers "F.Cu" "B.Cu")
		(net "GND")
	)
	(via
		(at 431.621438 -139.574778)
		(size 0.508)
		(drill 0.254)
		(layers "F.Cu" "B.Cu")
		(net "GND")
	)
	(via
		(at 386.541518 -401.492212)
		(size 0.4572)
		(drill 0.254)
		(layers "F.Cu" "B.Cu")
		(net "GND")
	)
	(via
		(at 33.767014 -267.866622)
		(size 0.4572)
		(drill 0.2032)
		(layers "F.Cu" "B.Cu")
		(net "GND")
	)
	(via
		(at 341.254334 -217.064336)
		(size 0.4572)
		(drill 0.2032)
		(layers "F.Cu" "B.Cu")
		(net "GND")
	)
	(via
		(at 291.460682 -303.566576)
		(size 0.4572)
		(drill 0.2032)
		(layers "F.Cu" "B.Cu")
		(net "GND")
	)
	(via
		(at 439.923682 -316.316614)
		(size 0.4572)
		(drill 0.2032)
		(layers "F.Cu" "B.Cu")
		(net "GND")
	)
	(via
		(at 296.794682 -226.216718)
		(size 0.4572)
		(drill 0.2032)
		(layers "F.Cu" "B.Cu")
		(net "GND")
	)
	(via
		(at 85.526118 -407.00452)
		(size 0.4064)
		(drill 0.2032)
		(layers "F.Cu" "B.Cu")
		(net "GND")
	)
	(via
		(at 69.250052 -437.34736)
		(size 0.4572)
		(drill 0.2032)
		(layers "F.Cu" "B.Cu")
		(net "GND")
	)
	(via
		(at 50.484278 -400.858228)
		(size 0.4064)
		(drill 0.2032)
		(layers "F.Cu" "B.Cu")
		(net "GND")
	)
	(via
		(at 337.604862 -272.639282)
		(size 0.4572)
		(drill 0.2032)
		(layers "F.Cu" "B.Cu")
		(net "GND")
	)
	(via
		(at 435.823614 -267.016738)
		(size 0.4572)
		(drill 0.2032)
		(layers "F.Cu" "B.Cu")
		(net "GND")
	)
	(via
		(at 54.508146 -204.96657)
		(size 0.4572)
		(drill 0.2032)
		(layers "F.Cu" "B.Cu")
		(net "GND")
	)
	(via
		(at 276.373082 -269.566644)
		(size 0.4572)
		(drill 0.2032)
		(layers "F.Cu" "B.Cu")
		(net "GND")
	)
	(via
		(at 312.972196 -404.51786)
		(size 0.4572)
		(drill 0.254)
		(layers "F.Cu" "B.Cu")
		(net "GND")
	)
	(via
		(at 417.292282 -288.266632)
		(size 0.4572)
		(drill 0.2032)
		(layers "F.Cu" "B.Cu")
		(net "GND")
	)
	(via
		(at 48.854614 -267.866622)
		(size 0.4572)
		(drill 0.2032)
		(layers "F.Cu" "B.Cu")
		(net "GND")
	)
	(via
		(at 43.520614 -261.066788)
		(size 0.4572)
		(drill 0.2032)
		(layers "F.Cu" "B.Cu")
		(net "GND")
	)
	(via
		(at 130.405886 -400.224244)
		(size 0.4572)
		(drill 0.254)
		(layers "F.Cu" "B.Cu")
		(net "GND")
	)
	(via
		(at 49.240694 -352.397822)
		(size 0.49022)
		(drill 0.254)
		(layers "F.Cu" "B.Cu")
		(net "GND")
	)
	(via
		(at 18.679414 -295.916604)
		(size 0.4572)
		(drill 0.2032)
		(layers "F.Cu" "B.Cu")
		(net "GND")
	)
	(via
		(at 52.10429 -400.224244)
		(size 0.4572)
		(drill 0.254)
		(layers "F.Cu" "B.Cu")
		(net "GND")
	)
	(via
		(at 409.540202 -205.816708)
		(size 0.4572)
		(drill 0.2032)
		(layers "F.Cu" "B.Cu")
		(net "GND")
	)
	(via
		(at 131.376166 -222.761556)
		(size 0.4572)
		(drill 0.2032)
		(layers "F.Cu" "B.Cu")
		(net "GND")
	)
	(via
		(at 14.579346 -231.316784)
		(size 0.4572)
		(drill 0.2032)
		(layers "F.Cu" "B.Cu")
		(net "GND")
	)
	(via
		(at 2.764536 -213.790022)
		(size 0.508)
		(drill 0.254)
		(layers "F.Cu" "B.Cu")
		(net "GND")
	)
	(via
		(at 62.051946 -231.316784)
		(size 0.4572)
		(drill 0.2032)
		(layers "F.Cu" "B.Cu")
		(net "GND")
	)
	(via
		(at 62.64021 -409.396184)
		(size 0.4572)
		(drill 0.254)
		(layers "F.Cu" "B.Cu")
		(net "GND")
	)
	(via
		(at 289.103054 -322.650358)
		(size 0.4572)
		(drill 0.2032)
		(layers "F.Cu" "B.Cu")
		(net "GND")
	)
	(via
		(at 125.625606 -406.370536)
		(size 0.4572)
		(drill 0.254)
		(layers "F.Cu" "B.Cu")
		(net "GND")
	)
	(via
		(at 383.075434 -232.528364)
		(size 0.4572)
		(drill 0.2032)
		(layers "F.Cu" "B.Cu")
		(net "GND")
	)
	(via
		(at 73.547478 -30.937962)
		(size 0.508)
		(drill 0.254)
		(layers "F.Cu" "B.Cu")
		(net "GND")
	)
	(via
		(at 321.250056 -436.051198)
		(size 0.4572)
		(drill 0.2032)
		(layers "F.Cu" "B.Cu")
		(net "GND")
	)
	(via
		(at 254.975614 -309.51678)
		(size 0.4572)
		(drill 0.2032)
		(layers "F.Cu" "B.Cu")
		(net "GND")
	)
	(via
		(at 409.748482 -226.216718)
		(size 0.4572)
		(drill 0.2032)
		(layers "F.Cu" "B.Cu")
		(net "GND")
	)
	(via
		(at 373.02948 -65.749678)
		(size 0.508)
		(drill 0.254)
		(layers "F.Cu" "B.Cu")
		(net "GND")
	)
	(via
		(at 419.348412 -18.235422)
		(size 0.508)
		(drill 0.254)
		(layers "F.Cu" "B.Cu")
		(net "GND")
	)
	(via
		(at 340.250018 -437.49976)
		(size 0.4572)
		(drill 0.2032)
		(layers "F.Cu" "B.Cu")
		(net "GND")
	)
	(via
		(at 107.520994 -282.405836)
		(size 0.4572)
		(drill 0.2032)
		(layers "F.Cu" "B.Cu")
		(net "GND")
	)
	(via
		(at 375.667016 -253.919736)
		(size 0.4572)
		(drill 0.2032)
		(layers "F.Cu" "B.Cu")
		(net "GND")
	)
	(via
		(at 272.273014 -300.166786)
		(size 0.4572)
		(drill 0.2032)
		(layers "F.Cu" "B.Cu")
		(net "GND")
	)
	(via
		(at 11.135614 -219.41663)
		(size 0.4572)
		(drill 0.2032)
		(layers "F.Cu" "B.Cu")
		(net "GND")
	)
	(via
		(at 138.336782 -401.492212)
		(size 0.4572)
		(drill 0.254)
		(layers "F.Cu" "B.Cu")
		(net "GND")
	)
	(via
		(at 127.907288 -358.784906)
		(size 0.508)
		(drill 0.254)
		(layers "F.Cu" "B.Cu")
		(net "GND")
	)
	(via
		(at 283.916882 -200.716642)
		(size 0.4572)
		(drill 0.2032)
		(layers "F.Cu" "B.Cu")
		(net "GND")
	)
	(via
		(at 110.340394 -282.405836)
		(size 0.4572)
		(drill 0.2032)
		(layers "F.Cu" "B.Cu")
		(net "GND")
	)
	(via
		(at 134.195566 -214.546434)
		(size 0.4572)
		(drill 0.2032)
		(layers "F.Cu" "B.Cu")
		(net "GND")
	)
	(via
		(at 418.741352 -323.429376)
		(size 0.4572)
		(drill 0.2032)
		(layers "F.Cu" "B.Cu")
		(net "GND")
	)
	(via
		(at 2.764536 -229.030022)
		(size 0.508)
		(drill 0.254)
		(layers "F.Cu" "B.Cu")
		(net "GND")
	)
	(via
		(at 347.363034 -240.667286)
		(size 0.4572)
		(drill 0.2032)
		(layers "F.Cu" "B.Cu")
		(net "GND")
	)
	(via
		(at 176.896014 -230.466646)
		(size 0.4572)
		(drill 0.2032)
		(layers "F.Cu" "B.Cu")
		(net "GND")
	)
	(via
		(at 116.449348 -279.964134)
		(size 0.4572)
		(drill 0.2032)
		(layers "F.Cu" "B.Cu")
		(net "GND")
	)
	(via
		(at 404.55977 -400.858228)
		(size 0.4064)
		(drill 0.2032)
		(layers "F.Cu" "B.Cu")
		(net "GND")
	)
	(via
		(at 367.678462 -279.150318)
		(size 0.4572)
		(drill 0.2032)
		(layers "F.Cu" "B.Cu")
		(net "GND")
	)
	(via
		(at 49.751996 -355.531928)
		(size 0.49022)
		(drill 0.254)
		(layers "F.Cu" "B.Cu")
		(net "GND")
	)
	(via
		(at 235.5088 -206.111348)
		(size 0.508)
		(drill 0.254)
		(layers "F.Cu" "B.Cu")
		(net "GND")
	)
	(via
		(at 209.281014 -295.916604)
		(size 0.4572)
		(drill 0.2032)
		(layers "F.Cu" "B.Cu")
		(net "GND")
	)
	(via
		(at 378.956062 -257.98907)
		(size 0.4572)
		(drill 0.2032)
		(layers "F.Cu" "B.Cu")
		(net "GND")
	)
	(via
		(at 92.954348 -271.825212)
		(size 0.4572)
		(drill 0.2032)
		(layers "F.Cu" "B.Cu")
		(net "GND")
	)
	(via
		(at 53.682392 -175.459898)
		(size 0.508)
		(drill 0.254)
		(layers "F.Cu" "B.Cu")
		(net "GND")
	)
	(via
		(at 156.355034 -400.858228)
		(size 0.4064)
		(drill 0.2032)
		(layers "F.Cu" "B.Cu")
		(net "GND")
	)
	(via
		(at 279.816814 -242.3668)
		(size 0.4572)
		(drill 0.2032)
		(layers "F.Cu" "B.Cu")
		(net "GND")
	)
	(via
		(at 92.365322 -333.833724)
		(size 0.508)
		(drill 0.254)
		(layers "F.Cu" "B.Cu")
		(net "GND")
	)
	(via
		(at 33.767014 -271.266666)
		(size 0.4572)
		(drill 0.2032)
		(layers "F.Cu" "B.Cu")
		(net "GND")
	)
	(via
		(at 2.764536 -127.430022)
		(size 0.508)
		(drill 0.254)
		(layers "F.Cu" "B.Cu")
		(net "GND")
	)
	(via
		(at 439.923682 -211.766658)
		(size 0.4572)
		(drill 0.2032)
		(layers "F.Cu" "B.Cu")
		(net "GND")
	)
	(via
		(at 186.649614 -312.91657)
		(size 0.4572)
		(drill 0.2032)
		(layers "F.Cu" "B.Cu")
		(net "GND")
	)
	(via
		(at 417.292282 -269.566644)
		(size 0.4572)
		(drill 0.2032)
		(layers "F.Cu" "B.Cu")
		(net "GND")
	)
	(via
		(at 99.532948 -265.314176)
		(size 0.4572)
		(drill 0.2032)
		(layers "F.Cu" "B.Cu")
		(net "GND")
	)
	(via
		(at 447.467482 -289.966654)
		(size 0.4572)
		(drill 0.2032)
		(layers "F.Cu" "B.Cu")
		(net "GND")
	)
	(via
		(at 400.053302 -403.249892)
		(size 0.4572)
		(drill 0.254)
		(layers "F.Cu" "B.Cu")
		(net "GND")
	)
	(via
		(at 328.133964 -441.225432)
		(size 0.508)
		(drill 0.254)
		(layers "F.Cu" "B.Cu")
		(net "GND")
	)
	(via
		(at 310.207914 -313.766708)
		(size 0.4572)
		(drill 0.2032)
		(layers "F.Cu" "B.Cu")
		(net "GND")
	)
	(via
		(at 417.292282 -316.316614)
		(size 0.4572)
		(drill 0.2032)
		(layers "F.Cu" "B.Cu")
		(net "GND")
	)
	(via
		(at 384.124962 -260.430772)
		(size 0.4318)
		(drill 0.2032)
		(layers "F.Cu" "B.Cu")
		(net "GND")
	)
	(via
		(at 108.68025 -237.86338)
		(size 0.4572)
		(drill 0.2032)
		(layers "F.Cu" "B.Cu")
		(net "GND")
	)
	(via
		(at 336.195162 -266.941808)
		(size 0.4572)
		(drill 0.2032)
		(layers "F.Cu" "B.Cu")
		(net "GND")
	)
	(via
		(at 205.180946 -251.716794)
		(size 0.4572)
		(drill 0.2032)
		(layers "F.Cu" "B.Cu")
		(net "GND")
	)
	(via
		(at 311.882282 -245.76659)
		(size 0.4572)
		(drill 0.2032)
		(layers "F.Cu" "B.Cu")
		(net "GND")
	)
	(via
		(at 254.975614 -260.21665)
		(size 0.4572)
		(drill 0.2032)
		(layers "F.Cu" "B.Cu")
		(net "GND")
	)
	(via
		(at 123.967748 -255.547622)
		(size 0.4572)
		(drill 0.2032)
		(layers "F.Cu" "B.Cu")
		(net "GND")
	)
	(via
		(at 136.532366 -400.224244)
		(size 0.4572)
		(drill 0.254)
		(layers "F.Cu" "B.Cu")
		(net "GND")
	)
	(via
		(at 210.94192 -134.065518)
		(size 0.508)
		(drill 0.254)
		(layers "F.Cu" "B.Cu")
		(net "GND")
	)
	(via
		(at 107.051348 -283.219906)
		(size 0.4572)
		(drill 0.2032)
		(layers "F.Cu" "B.Cu")
		(net "GND")
	)
	(via
		(at 422.650412 -19.125438)
		(size 0.508)
		(drill 0.254)
		(layers "F.Cu" "B.Cu")
		(net "GND")
	)
	(via
		(at 28.433014 -210.066636)
		(size 0.4572)
		(drill 0.2032)
		(layers "F.Cu" "B.Cu")
		(net "GND")
	)
	(via
		(at 98.953066 -226.831144)
		(size 0.4572)
		(drill 0.2032)
		(layers "F.Cu" "B.Cu")
		(net "GND")
	)
	(via
		(at 262.519414 -233.016806)
		(size 0.4572)
		(drill 0.2032)
		(layers "F.Cu" "B.Cu")
		(net "GND")
	)
	(via
		(at 449.841366 -74.971656)
		(size 0.508)
		(drill 0.254)
		(layers "F.Cu" "B.Cu")
		(net "GND")
	)
	(via
		(at 368.916204 -258.45135)
		(size 0.4572)
		(drill 0.2032)
		(layers "F.Cu" "B.Cu")
		(net "GND")
	)
	(via
		(at 386.350002 -437.49976)
		(size 0.4572)
		(drill 0.2032)
		(layers "F.Cu" "B.Cu")
		(net "GND")
	)
	(via
		(at 12.5476 -97.635568)
		(size 0.508)
		(drill 0.254)
		(layers "F.Cu" "B.Cu")
		(net "GND")
	)
	(via
		(at 360.05008 -236.597952)
		(size 0.4572)
		(drill 0.2032)
		(layers "F.Cu" "B.Cu")
		(net "GND")
	)
	(via
		(at 405.349964 -427.699678)
		(size 0.4572)
		(drill 0.2032)
		(layers "F.Cu" "B.Cu")
		(net "GND")
	)
	(via
		(at 458.455014 -313.766708)
		(size 0.4572)
		(drill 0.2032)
		(layers "F.Cu" "B.Cu")
		(net "GND")
	)
	(via
		(at 58.824114 -210.066636)
		(size 0.4572)
		(drill 0.2032)
		(layers "F.Cu" "B.Cu")
		(net "GND")
	)
	(via
		(at 385.493768 -344.90533)
		(size 0.49022)
		(drill 0.254)
		(layers "F.Cu" "B.Cu")
		(net "GND")
	)
	(via
		(at 414.657286 -182.999126)
		(size 0.508)
		(drill 0.254)
		(layers "F.Cu" "B.Cu")
		(net "GND")
	)
	(via
		(at 287.434528 -412.996126)
		(size 0.508)
		(drill 0.254)
		(layers "F.Cu" "B.Cu")
		(net "GND")
	)
	(via
		(at 299.004482 -262.76681)
		(size 0.4572)
		(drill 0.2032)
		(layers "F.Cu" "B.Cu")
		(net "GND")
	)
	(via
		(at 176.896014 -228.766624)
		(size 0.4572)
		(drill 0.2032)
		(layers "F.Cu" "B.Cu")
		(net "GND")
	)
	(via
		(at 46.964346 -236.416596)
		(size 0.4572)
		(drill 0.2032)
		(layers "F.Cu" "B.Cu")
		(net "GND")
	)
	(via
		(at 104.231948 -273.453098)
		(size 0.4572)
		(drill 0.2032)
		(layers "F.Cu" "B.Cu")
		(net "GND")
	)
	(via
		(at 64.743838 -323.60616)
		(size 0.4572)
		(drill 0.2032)
		(layers "F.Cu" "B.Cu")
		(net "GND")
	)
	(via
		(at 413.349948 -433.747164)
		(size 0.4572)
		(drill 0.2032)
		(layers "F.Cu" "B.Cu")
		(net "GND")
	)
	(via
		(at 16.789146 -223.666558)
		(size 0.4572)
		(drill 0.2032)
		(layers "F.Cu" "B.Cu")
		(net "GND")
	)
	(via
		(at 413.192214 -250.016772)
		(size 0.4572)
		(drill 0.2032)
		(layers "F.Cu" "B.Cu")
		(net "GND")
	)
	(via
		(at 274.163282 -286.56661)
		(size 0.4572)
		(drill 0.2032)
		(layers "F.Cu" "B.Cu")
		(net "GND")
	)
	(via
		(at 311.666382 -282.316682)
		(size 0.4572)
		(drill 0.2032)
		(layers "F.Cu" "B.Cu")
		(net "GND")
	)
	(via
		(at 455.011282 -295.916604)
		(size 0.4572)
		(drill 0.2032)
		(layers "F.Cu" "B.Cu")
		(net "GND")
	)
	(via
		(at 90.667586 -400.200368)
		(size 0.4572)
		(drill 0.254)
		(layers "F.Cu" "B.Cu")
		(net "GND")
	)
	(via
		(at 145.349976 -437.34736)
		(size 0.4572)
		(drill 0.2032)
		(layers "F.Cu" "B.Cu")
		(net "GND")
	)
	(via
		(at 385.424934 -225.203258)
		(size 0.4572)
		(drill 0.2032)
		(layers "F.Cu" "B.Cu")
		(net "GND")
	)
	(via
		(at 32.947102 -10.16508)
		(size 0.508)
		(drill 0.254)
		(layers "F.Cu" "B.Cu")
		(net "GND")
	)
	(via
		(at 460.664814 -309.51678)
		(size 0.4572)
		(drill 0.2032)
		(layers "F.Cu" "B.Cu")
		(net "GND")
	)
	(via
		(at 371.32768 -249.620024)
		(size 0.4572)
		(drill 0.2032)
		(layers "F.Cu" "B.Cu")
		(net "GND")
	)
	(via
		(at 331.881988 -56.438546)
		(size 0.4572)
		(drill 0.2032)
		(layers "F.Cu" "B.Cu")
		(net "GND")
	)
	(via
		(at 144.005046 -407.638504)
		(size 0.4572)
		(drill 0.254)
		(layers "F.Cu" "B.Cu")
		(net "GND")
	)
	(via
		(at 85.178646 -250.428506)
		(size 0.4572)
		(drill 0.2032)
		(layers "F.Cu" "B.Cu")
		(net "GND")
	)
	(via
		(at 212.559138 -193.67373)
		(size 0.508)
		(drill 0.254)
		(layers "F.Cu" "B.Cu")
		(net "GND")
	)
	(via
		(at 19.193256 -383.527808)
		(size 0.508)
		(drill 0.254)
		(layers "F.Cu" "B.Cu")
		(net "GND")
	)
	(via
		(at 457.221082 -269.566644)
		(size 0.4572)
		(drill 0.2032)
		(layers "F.Cu" "B.Cu")
		(net "GND")
	)
	(via
		(at 141.656054 -93.757242)
		(size 0.508)
		(drill 0.254)
		(layers "F.Cu" "B.Cu")
		(net "GND")
	)
	(via
		(at 458.455014 -289.11677)
		(size 0.4572)
		(drill 0.2032)
		(layers "F.Cu" "B.Cu")
		(net "GND")
	)
	(via
		(at 432.379882 -301.01667)
		(size 0.4572)
		(drill 0.2032)
		(layers "F.Cu" "B.Cu")
		(net "GND")
	)
	(via
		(at 127.616966 -219.506038)
		(size 0.4572)
		(drill 0.2032)
		(layers "F.Cu" "B.Cu")
		(net "GND")
	)
	(via
		(at 450.911214 -304.416714)
		(size 0.4572)
		(drill 0.2032)
		(layers "F.Cu" "B.Cu")
		(net "GND")
	)
	(via
		(at 344.07348 -228.45903)
		(size 0.4572)
		(drill 0.2032)
		(layers "F.Cu" "B.Cu")
		(net "GND")
	)
	(via
		(at 66.152014 -289.966654)
		(size 0.4572)
		(drill 0.2032)
		(layers "F.Cu" "B.Cu")
		(net "GND")
	)
	(via
		(at 331.700886 -82.490056)
		(size 0.508)
		(drill 0.254)
		(layers "F.Cu" "B.Cu")
		(net "GND")
	)
	(via
		(at 355.461062 -285.661354)
		(size 0.4572)
		(drill 0.2032)
		(layers "F.Cu" "B.Cu")
		(net "GND")
	)
	(via
		(at 306.548282 -284.866588)
		(size 0.4572)
		(drill 0.2032)
		(layers "F.Cu" "B.Cu")
		(net "GND")
	)
	(via
		(at 402.278596 -18.235422)
		(size 0.508)
		(drill 0.254)
		(layers "F.Cu" "B.Cu")
		(net "GND")
	)
	(via
		(at 421.502332 -170.471846)
		(size 0.508)
		(drill 0.254)
		(layers "F.Cu" "B.Cu")
		(net "GND")
	)
	(via
		(at 332.336648 -407.00452)
		(size 0.4064)
		(drill 0.2032)
		(layers "F.Cu" "B.Cu")
		(net "GND")
	)
	(via
		(at 413.349948 -431.29962)
		(size 0.4572)
		(drill 0.2032)
		(layers "F.Cu" "B.Cu")
		(net "GND")
	)
	(via
		(at 202.971146 -261.916672)
		(size 0.4572)
		(drill 0.2032)
		(layers "F.Cu" "B.Cu")
		(net "GND")
	)
	(via
		(at 309.992014 -231.316784)
		(size 0.4572)
		(drill 0.2032)
		(layers "F.Cu" "B.Cu")
		(net "GND")
	)
	(via
		(at 298.924218 -322.587366)
		(size 0.4572)
		(drill 0.2032)
		(layers "F.Cu" "B.Cu")
		(net "GND")
	)
	(via
		(at 128.35001 -427.699678)
		(size 0.4572)
		(drill 0.2032)
		(layers "F.Cu" "B.Cu")
		(net "GND")
	)
	(via
		(at 443.367414 -204.96657)
		(size 0.4572)
		(drill 0.2032)
		(layers "F.Cu" "B.Cu")
		(net "GND")
	)
	(via
		(at 370.51488 -42.128948)
		(size 0.508)
		(drill 0.254)
		(layers "F.Cu" "B.Cu")
		(net "GND")
	)
	(via
		(at 387.800342 -404.51786)
		(size 0.4572)
		(drill 0.254)
		(layers "F.Cu" "B.Cu")
		(net "GND")
	)
	(via
		(at 96.243394 -254.733552)
		(size 0.4572)
		(drill 0.2032)
		(layers "F.Cu" "B.Cu")
		(net "GND")
	)
	(via
		(at 105.171494 -284.847538)
		(size 0.4572)
		(drill 0.2032)
		(layers "F.Cu" "B.Cu")
		(net "GND")
	)
	(via
		(at 124.437394 -269.38351)
		(size 0.4572)
		(drill 0.2032)
		(layers "F.Cu" "B.Cu")
		(net "GND")
	)
	(via
		(at 455.011282 -312.91657)
		(size 0.4572)
		(drill 0.2032)
		(layers "F.Cu" "B.Cu")
		(net "GND")
	)
	(via
		(at 191.983614 -224.516696)
		(size 0.4572)
		(drill 0.2032)
		(layers "F.Cu" "B.Cu")
		(net "GND")
	)
	(via
		(at 458.455014 -315.46673)
		(size 0.4572)
		(drill 0.2032)
		(layers "F.Cu" "B.Cu")
		(net "GND")
	)
	(via
		(at 287.360614 -306.116736)
		(size 0.4572)
		(drill 0.2032)
		(layers "F.Cu" "B.Cu")
		(net "GND")
	)
	(via
		(at 438.033414 -311.216802)
		(size 0.4572)
		(drill 0.2032)
		(layers "F.Cu" "B.Cu")
		(net "GND")
	)
	(via
		(at 108.460794 -271.011396)
		(size 0.4572)
		(drill 0.2032)
		(layers "F.Cu" "B.Cu")
		(net "GND")
	)
	(via
		(at 121.216166 -400.224244)
		(size 0.4572)
		(drill 0.254)
		(layers "F.Cu" "B.Cu")
		(net "GND")
	)
	(via
		(at 246.984266 -129.362962)
		(size 0.508)
		(drill 0.254)
		(layers "F.Cu" "B.Cu")
		(net "GND")
	)
	(via
		(at 42.048684 -323.434456)
		(size 0.4572)
		(drill 0.2032)
		(layers "F.Cu" "B.Cu")
		(net "GND")
	)
	(via
		(at 197.637146 -244.916706)
		(size 0.4572)
		(drill 0.2032)
		(layers "F.Cu" "B.Cu")
		(net "GND")
	)
	(via
		(at 191.983614 -210.066636)
		(size 0.4572)
		(drill 0.2032)
		(layers "F.Cu" "B.Cu")
		(net "GND")
	)
	(via
		(at 137.124694 -281.59202)
		(size 0.4572)
		(drill 0.2032)
		(layers "F.Cu" "B.Cu")
		(net "GND")
	)
	(via
		(at 262.519414 -234.716574)
		(size 0.4572)
		(drill 0.2032)
		(layers "F.Cu" "B.Cu")
		(net "GND")
	)
	(via
		(at 377.546362 -258.80314)
		(size 0.4572)
		(drill 0.2032)
		(layers "F.Cu" "B.Cu")
		(net "GND")
	)
	(via
		(at 29.666946 -244.916706)
		(size 0.4572)
		(drill 0.2032)
		(layers "F.Cu" "B.Cu")
		(net "GND")
	)
	(via
		(at 15.415768 -22.127972)
		(size 0.508)
		(drill 0.254)
		(layers "F.Cu" "B.Cu")
		(net "GND")
	)
	(via
		(at 186.649614 -238.116618)
		(size 0.4572)
		(drill 0.2032)
		(layers "F.Cu" "B.Cu")
		(net "GND")
	)
	(via
		(at 283.916882 -266.1666)
		(size 0.4572)
		(drill 0.2032)
		(layers "F.Cu" "B.Cu")
		(net "GND")
	)
	(via
		(at 171.562014 -241.516662)
		(size 0.4572)
		(drill 0.2032)
		(layers "F.Cu" "B.Cu")
		(net "GND")
	)
	(via
		(at 216.38133 -40.706548)
		(size 0.508)
		(drill 0.254)
		(layers "F.Cu" "B.Cu")
		(net "GND")
	)
	(via
		(at 449.677282 -244.066568)
		(size 0.4572)
		(drill 0.2032)
		(layers "F.Cu" "B.Cu")
		(net "GND")
	)
	(via
		(at 161.808414 -222.816674)
		(size 0.4572)
		(drill 0.2032)
		(layers "F.Cu" "B.Cu")
		(net "GND")
	)
	(via
		(at 59.626246 -273.816572)
		(size 0.4572)
		(drill 0.2032)
		(layers "F.Cu" "B.Cu")
		(net "GND")
	)
	(via
		(at 302.002444 -360.143298)
		(size 0.508)
		(drill 0.254)
		(layers "F.Cu" "B.Cu")
		(net "GND")
	)
	(via
		(at 35.976814 -213.46668)
		(size 0.4572)
		(drill 0.2032)
		(layers "F.Cu" "B.Cu")
		(net "GND")
	)
	(via
		(at 321.800728 -403.883876)
		(size 0.4064)
		(drill 0.2032)
		(layers "F.Cu" "B.Cu")
		(net "GND")
	)
	(via
		(at 300.238414 -296.766742)
		(size 0.4572)
		(drill 0.2032)
		(layers "F.Cu" "B.Cu")
		(net "GND")
	)
	(via
		(at 449.677282 -312.91657)
		(size 0.4572)
		(drill 0.2032)
		(layers "F.Cu" "B.Cu")
		(net "GND")
	)
	(via
		(at 419.502082 -239.81664)
		(size 0.4572)
		(drill 0.2032)
		(layers "F.Cu" "B.Cu")
		(net "GND")
	)
	(via
		(at 270.063214 -240.666778)
		(size 0.4572)
		(drill 0.2032)
		(layers "F.Cu" "B.Cu")
		(net "GND")
	)
	(via
		(at 134.305548 -275.08073)
		(size 0.4572)
		(drill 0.2032)
		(layers "F.Cu" "B.Cu")
		(net "GND")
	)
	(via
		(at 453.435212 -22.079458)
		(size 0.508)
		(drill 0.254)
		(layers "F.Cu" "B.Cu")
		(net "GND")
	)
	(via
		(at 405.385524 -6.07949)
		(size 0.508)
		(drill 0.254)
		(layers "F.Cu" "B.Cu")
		(net "GND")
	)
	(via
		(at 377.436634 -219.506038)
		(size 0.4572)
		(drill 0.2032)
		(layers "F.Cu" "B.Cu")
		(net "GND")
	)
	(via
		(at 384.125216 -288.103056)
		(size 0.4572)
		(drill 0.2032)
		(layers "F.Cu" "B.Cu")
		(net "GND")
	)
	(via
		(at 352.280474 -171.571412)
		(size 0.508)
		(drill 0.254)
		(layers "F.Cu" "B.Cu")
		(net "GND")
	)
	(via
		(at 72.191118 -410.030168)
		(size 0.4064)
		(drill 0.2032)
		(layers "F.Cu" "B.Cu")
		(net "GND")
	)
	(via
		(at 409.748482 -204.116686)
		(size 0.4572)
		(drill 0.2032)
		(layers "F.Cu" "B.Cu")
		(net "GND")
	)
	(via
		(at 55.528718 -400.858228)
		(size 0.4064)
		(drill 0.2032)
		(layers "F.Cu" "B.Cu")
		(net "GND")
	)
	(via
		(at 171.562014 -224.516696)
		(size 0.4572)
		(drill 0.2032)
		(layers "F.Cu" "B.Cu")
		(net "GND")
	)
	(via
		(at 332.796134 -247.992138)
		(size 0.4572)
		(drill 0.2032)
		(layers "F.Cu" "B.Cu")
		(net "GND")
	)
	(via
		(at 133.365748 -281.59202)
		(size 0.4572)
		(drill 0.2032)
		(layers "F.Cu" "B.Cu")
		(net "GND")
	)
	(via
		(at 102.928674 -255.231392)
		(size 0.4572)
		(drill 0.2032)
		(layers "F.Cu" "B.Cu")
		(net "GND")
	)
	(via
		(at 123.857766 -219.506038)
		(size 0.4572)
		(drill 0.2032)
		(layers "F.Cu" "B.Cu")
		(net "GND")
	)
	(via
		(at 383.545334 -233.34218)
		(size 0.4572)
		(drill 0.2032)
		(layers "F.Cu" "B.Cu")
		(net "GND")
	)
	(via
		(at 150.492714 -410.030168)
		(size 0.4064)
		(drill 0.2032)
		(layers "F.Cu" "B.Cu")
		(net "GND")
	)
	(via
		(at 255.651 -67.782948)
		(size 0.508)
		(drill 0.254)
		(layers "F.Cu" "B.Cu")
		(net "GND")
	)
	(via
		(at 317.655448 -403.883876)
		(size 0.4064)
		(drill 0.2032)
		(layers "F.Cu" "B.Cu")
		(net "GND")
	)
	(via
		(at 53.6829 -345.642438)
		(size 0.508)
		(drill 0.254)
		(layers "F.Cu" "B.Cu")
		(net "GND")
	)
	(via
		(at 300.238414 -227.066602)
		(size 0.4572)
		(drill 0.2032)
		(layers "F.Cu" "B.Cu")
		(net "GND")
	)
	(via
		(at 197.637146 -248.31675)
		(size 0.4572)
		(drill 0.2032)
		(layers "F.Cu" "B.Cu")
		(net "GND")
	)
	(via
		(at 56.610758 -403.883876)
		(size 0.4064)
		(drill 0.2032)
		(layers "F.Cu" "B.Cu")
		(net "GND")
	)
	(via
		(at 291.460682 -269.566644)
		(size 0.4572)
		(drill 0.2032)
		(layers "F.Cu" "B.Cu")
		(net "GND")
	)
	(via
		(at 350.774762 -248.658126)
		(size 0.4572)
		(drill 0.2032)
		(layers "F.Cu" "B.Cu")
		(net "GND")
	)
	(via
		(at 20.889214 -261.066788)
		(size 0.4572)
		(drill 0.2032)
		(layers "F.Cu" "B.Cu")
		(net "GND")
	)
	(via
		(at 21.96846 -52.999894)
		(size 0.508)
		(drill 0.254)
		(layers "F.Cu" "B.Cu")
		(net "GND")
	)
	(via
		(at 79.399638 -407.00452)
		(size 0.4064)
		(drill 0.2032)
		(layers "F.Cu" "B.Cu")
		(net "GND")
	)
	(via
		(at 382.135634 -230.900478)
		(size 0.4572)
		(drill 0.2032)
		(layers "F.Cu" "B.Cu")
		(net "GND")
	)
	(via
		(at 145.349976 -436.051198)
		(size 0.4572)
		(drill 0.2032)
		(layers "F.Cu" "B.Cu")
		(net "GND")
	)
	(via
		(at 283.916882 -295.916604)
		(size 0.4572)
		(drill 0.2032)
		(layers "F.Cu" "B.Cu")
		(net "GND")
	)
	(via
		(at 383.545334 -223.575626)
		(size 0.4572)
		(drill 0.2032)
		(layers "F.Cu" "B.Cu")
		(net "GND")
	)
	(via
		(at 210.160362 -72.80275)
		(size 0.508)
		(drill 0.254)
		(layers "F.Cu" "B.Cu")
		(net "GND")
	)
	(via
		(at 18.679414 -239.81664)
		(size 0.4572)
		(drill 0.2032)
		(layers "F.Cu" "B.Cu")
		(net "GND")
	)
	(via
		(at 299.004482 -299.316648)
		(size 0.4572)
		(drill 0.2032)
		(layers "F.Cu" "B.Cu")
		(net "GND")
	)
	(via
		(at 266.619482 -219.41663)
		(size 0.4572)
		(drill 0.2032)
		(layers "F.Cu" "B.Cu")
		(net "GND")
	)
	(via
		(at 259.075682 -210.066636)
		(size 0.4572)
		(drill 0.2032)
		(layers "F.Cu" "B.Cu")
		(net "GND")
	)
	(via
		(at 430.489614 -221.96679)
		(size 0.4572)
		(drill 0.2032)
		(layers "F.Cu" "B.Cu")
		(net "GND")
	)
	(via
		(at 24.332946 -250.016772)
		(size 0.4572)
		(drill 0.2032)
		(layers "F.Cu" "B.Cu")
		(net "GND")
	)
	(via
		(at 62.267846 -206.666592)
		(size 0.4572)
		(drill 0.2032)
		(layers "F.Cu" "B.Cu")
		(net "GND")
	)
	(via
		(at 337.49488 -228.45903)
		(size 0.4572)
		(drill 0.2032)
		(layers "F.Cu" "B.Cu")
		(net "GND")
	)
	(via
		(at 109.760766 -216.25052)
		(size 0.4572)
		(drill 0.2032)
		(layers "F.Cu" "B.Cu")
		(net "GND")
	)
	(via
		(at 157.505146 -283.166566)
		(size 0.4572)
		(drill 0.2032)
		(layers "F.Cu" "B.Cu")
		(net "GND")
	)
	(via
		(at 304.338482 -204.116686)
		(size 0.4572)
		(drill 0.2032)
		(layers "F.Cu" "B.Cu")
		(net "GND")
	)
	(via
		(at 140.349986 -436.051198)
		(size 0.4572)
		(drill 0.2032)
		(layers "F.Cu" "B.Cu")
		(net "GND")
	)
	(via
		(at 110.700566 -229.272846)
		(size 0.4572)
		(drill 0.2032)
		(layers "F.Cu" "B.Cu")
		(net "GND")
	)
	(via
		(at 20.889214 -316.316614)
		(size 0.4572)
		(drill 0.2032)
		(layers "F.Cu" "B.Cu")
		(net "GND")
	)
	(via
		(at 209.281014 -245.76659)
		(size 0.4572)
		(drill 0.2032)
		(layers "F.Cu" "B.Cu")
		(net "GND")
	)
	(via
		(at 138.336782 -403.249892)
		(size 0.4572)
		(drill 0.254)
		(layers "F.Cu" "B.Cu")
		(net "GND")
	)
	(via
		(at 207.071214 -291.666676)
		(size 0.4572)
		(drill 0.2032)
		(layers "F.Cu" "B.Cu")
		(net "GND")
	)
	(via
		(at 405.648414 -234.716574)
		(size 0.4572)
		(drill 0.2032)
		(layers "F.Cu" "B.Cu")
		(net "GND")
	)
	(via
		(at 135.71474 -259.616956)
		(size 0.4572)
		(drill 0.2032)
		(layers "F.Cu" "B.Cu")
		(net "GND")
	)
	(via
		(at 11.135614 -314.616592)
		(size 0.4572)
		(drill 0.2032)
		(layers "F.Cu" "B.Cu")
		(net "GND")
	)
	(via
		(at 227.838 -226.54133)
		(size 0.508)
		(drill 0.254)
		(layers "F.Cu" "B.Cu")
		(net "GND")
	)
	(via
		(at 262.519414 -244.916706)
		(size 0.4572)
		(drill 0.2032)
		(layers "F.Cu" "B.Cu")
		(net "GND")
	)
	(via
		(at 417.063682 -272.966688)
		(size 0.4572)
		(drill 0.2032)
		(layers "F.Cu" "B.Cu")
		(net "GND")
	)
	(via
		(at 44.61256 -115.259866)
		(size 0.508)
		(drill 0.254)
		(layers "F.Cu" "B.Cu")
		(net "GND")
	)
	(via
		(at 450.911214 -195.616576)
		(size 0.4572)
		(drill 0.2032)
		(layers "F.Cu" "B.Cu")
		(net "GND")
	)
	(via
		(at 407.858214 -265.316716)
		(size 0.4572)
		(drill 0.2032)
		(layers "F.Cu" "B.Cu")
		(net "GND")
	)
	(via
		(at 365.76381 -246.669306)
		(size 0.4572)
		(drill 0.2032)
		(layers "F.Cu" "B.Cu")
		(net "GND")
	)
	(via
		(at 294.904414 -298.466764)
		(size 0.4572)
		(drill 0.2032)
		(layers "F.Cu" "B.Cu")
		(net "GND")
	)
	(via
		(at 415.402014 -268.71676)
		(size 0.4572)
		(drill 0.2032)
		(layers "F.Cu" "B.Cu")
		(net "GND")
	)
	(via
		(at 302.895 -418.069268)
		(size 0.508)
		(drill 0.254)
		(layers "F.Cu" "B.Cu")
		(net "GND")
	)
	(via
		(at 285.150814 -216.016586)
		(size 0.4572)
		(drill 0.2032)
		(layers "F.Cu" "B.Cu")
		(net "GND")
	)
	(via
		(at 99.062794 -282.405836)
		(size 0.4572)
		(drill 0.2032)
		(layers "F.Cu" "B.Cu")
		(net "GND")
	)
	(via
		(at 66.152014 -221.116652)
		(size 0.4572)
		(drill 0.2032)
		(layers "F.Cu" "B.Cu")
		(net "GND")
	)
	(via
		(at 56.182514 -288.266632)
		(size 0.4572)
		(drill 0.2032)
		(layers "F.Cu" "B.Cu")
		(net "GND")
	)
	(via
		(at 364.389416 -286.475424)
		(size 0.4572)
		(drill 0.2032)
		(layers "F.Cu" "B.Cu")
		(net "GND")
	)
	(via
		(at 275.612352 -323.429376)
		(size 0.4572)
		(drill 0.2032)
		(layers "F.Cu" "B.Cu")
		(net "GND")
	)
	(via
		(at 26.512266 -18.246344)
		(size 0.508)
		(drill 0.254)
		(layers "F.Cu" "B.Cu")
		(net "GND")
	)
	(via
		(at 74.04608 -3.241548)
		(size 0.508)
		(drill 0.254)
		(layers "F.Cu" "B.Cu")
		(net "GND")
	)
	(via
		(at 345.013534 -213.732618)
		(size 0.4572)
		(drill 0.2032)
		(layers "F.Cu" "B.Cu")
		(net "GND")
	)
	(via
		(at 335.255362 -288.103056)
		(size 0.4572)
		(drill 0.2032)
		(layers "F.Cu" "B.Cu")
		(net "GND")
	)
	(via
		(at 320.3575 -401.492212)
		(size 0.4572)
		(drill 0.254)
		(layers "F.Cu" "B.Cu")
		(net "GND")
	)
	(via
		(at 161.038286 -404.51786)
		(size 0.4572)
		(drill 0.254)
		(layers "F.Cu" "B.Cu")
		(net "GND")
	)
	(via
		(at 199.527414 -308.666642)
		(size 0.4572)
		(drill 0.2032)
		(layers "F.Cu" "B.Cu")
		(net "GND")
	)
	(via
		(at 194.193414 -213.46668)
		(size 0.4572)
		(drill 0.2032)
		(layers "F.Cu" "B.Cu")
		(net "GND")
	)
	(via
		(at 20.889214 -207.51673)
		(size 0.4572)
		(drill 0.2032)
		(layers "F.Cu" "B.Cu")
		(net "GND")
	)
	(via
		(at 98.483166 -222.761556)
		(size 0.4572)
		(drill 0.2032)
		(layers "F.Cu" "B.Cu")
		(net "GND")
	)
	(via
		(at 283.916882 -258.516628)
		(size 0.4572)
		(drill 0.2032)
		(layers "F.Cu" "B.Cu")
		(net "GND")
	)
	(via
		(at 375.087134 -223.575626)
		(size 0.4572)
		(drill 0.2032)
		(layers "F.Cu" "B.Cu")
		(net "GND")
	)
	(via
		(at 375.196862 -287.28924)
		(size 0.4572)
		(drill 0.2032)
		(layers "F.Cu" "B.Cu")
		(net "GND")
	)
	(via
		(at 43.587924 -6.090412)
		(size 0.508)
		(drill 0.254)
		(layers "F.Cu" "B.Cu")
		(net "GND")
	)
	(via
		(at 216.824814 -247.466612)
		(size 0.4572)
		(drill 0.2032)
		(layers "F.Cu" "B.Cu")
		(net "GND")
	)
	(via
		(at 367.208816 -281.59202)
		(size 0.4572)
		(drill 0.2032)
		(layers "F.Cu" "B.Cu")
		(net "GND")
	)
	(via
		(at 464.764882 -213.46668)
		(size 0.4572)
		(drill 0.2032)
		(layers "F.Cu" "B.Cu")
		(net "GND")
	)
	(via
		(at 453.121014 -238.966756)
		(size 0.4572)
		(drill 0.2032)
		(layers "F.Cu" "B.Cu")
		(net "GND")
	)
	(via
		(at 412.306262 -401.492212)
		(size 0.4572)
		(drill 0.254)
		(layers "F.Cu" "B.Cu")
		(net "GND")
	)
	(via
		(at 289.250882 -221.116652)
		(size 0.4572)
		(drill 0.2032)
		(layers "F.Cu" "B.Cu")
		(net "GND")
	)
	(via
		(at 408.082242 -217.716608)
		(size 0.4572)
		(drill 0.2032)
		(layers "F.Cu" "B.Cu")
		(net "GND")
	)
	(via
		(at 20.889214 -266.1666)
		(size 0.4572)
		(drill 0.2032)
		(layers "F.Cu" "B.Cu")
		(net "GND")
	)
	(via
		(at 165.544754 -403.883876)
		(size 0.4064)
		(drill 0.2032)
		(layers "F.Cu" "B.Cu")
		(net "GND")
	)
	(via
		(at 57.024524 -177.327052)
		(size 0.508)
		(drill 0.254)
		(layers "F.Cu" "B.Cu")
		(net "GND")
	)
	(via
		(at 93.784166 -219.506038)
		(size 0.4572)
		(drill 0.2032)
		(layers "F.Cu" "B.Cu")
		(net "GND")
	)
	(via
		(at 259.51688 -152.872948)
		(size 0.508)
		(drill 0.254)
		(layers "F.Cu" "B.Cu")
		(net "GND")
	)
	(via
		(at 131.486148 -281.59202)
		(size 0.4572)
		(drill 0.2032)
		(layers "F.Cu" "B.Cu")
		(net "GND")
	)
	(via
		(at 93.730826 -404.51786)
		(size 0.4572)
		(drill 0.254)
		(layers "F.Cu" "B.Cu")
		(net "GND")
	)
	(via
		(at 344.36431 -52.679346)
		(size 0.4572)
		(drill 0.2032)
		(layers "F.Cu" "B.Cu")
		(net "GND")
	)
	(via
		(at 418.79393 -403.883876)
		(size 0.4064)
		(drill 0.2032)
		(layers "F.Cu" "B.Cu")
		(net "GND")
	)
	(via
		(at 450.911214 -231.316784)
		(size 0.4572)
		(drill 0.2032)
		(layers "F.Cu" "B.Cu")
		(net "GND")
	)
	(via
		(at 139.682982 -407.638504)
		(size 0.4572)
		(drill 0.254)
		(layers "F.Cu" "B.Cu")
		(net "GND")
	)
	(via
		(at 148.511514 -410.030168)
		(size 0.4064)
		(drill 0.2032)
		(layers "F.Cu" "B.Cu")
		(net "GND")
	)
	(via
		(at 266.619482 -314.616592)
		(size 0.4572)
		(drill 0.2032)
		(layers "F.Cu" "B.Cu")
		(net "GND")
	)
	(via
		(at 409.748482 -221.116652)
		(size 0.4572)
		(drill 0.2032)
		(layers "F.Cu" "B.Cu")
		(net "GND")
	)
	(via
		(at 158.062422 -410.664152)
		(size 0.4572)
		(drill 0.254)
		(layers "F.Cu" "B.Cu")
		(net "GND")
	)
	(via
		(at 157.708346 -199.01662)
		(size 0.4572)
		(drill 0.2032)
		(layers "F.Cu" "B.Cu")
		(net "GND")
	)
	(via
		(at 13.345414 -314.616592)
		(size 0.4572)
		(drill 0.2032)
		(layers "F.Cu" "B.Cu")
		(net "GND")
	)
	(via
		(at 216.824814 -222.816674)
		(size 0.4572)
		(drill 0.2032)
		(layers "F.Cu" "B.Cu")
		(net "GND")
	)
	(via
		(at 365.76381 -242.960906)
		(size 0.4572)
		(drill 0.2032)
		(layers "F.Cu" "B.Cu")
		(net "GND")
	)
	(via
		(at 65.25006 -428.851314)
		(size 0.4572)
		(drill 0.2032)
		(layers "F.Cu" "B.Cu")
		(net "GND")
	)
	(via
		(at 197.1294 -95.2754)
		(size 0.508)
		(drill 0.254)
		(layers "F.Cu" "B.Cu")
		(net "GND")
	)
	(via
		(at 254.975614 -267.016738)
		(size 0.4572)
		(drill 0.2032)
		(layers "F.Cu" "B.Cu")
		(net "GND")
	)
	(via
		(at 136.545066 -233.34218)
		(size 0.4318)
		(drill 0.2032)
		(layers "F.Cu" "B.Cu")
		(net "GND")
	)
	(via
		(at 123.036584 -40.986456)
		(size 0.508)
		(drill 0.254)
		(layers "F.Cu" "B.Cu")
		(net "GND")
	)
	(via
		(at 105.689146 -339.234272)
		(size 0.508)
		(drill 0.254)
		(layers "F.Cu" "B.Cu")
		(net "GND")
	)
	(via
		(at 117.858794 -266.128246)
		(size 0.4572)
		(drill 0.2032)
		(layers "F.Cu" "B.Cu")
		(net "GND")
	)
	(via
		(at 175.31588 -131.280408)
		(size 0.508)
		(drill 0.254)
		(layers "F.Cu" "B.Cu")
		(net "GND")
	)
	(via
		(at 349.3262 -52.939188)
		(size 0.508)
		(drill 0.254)
		(layers "F.Cu" "B.Cu")
		(net "GND")
	)
	(via
		(at 302.664114 -276.366732)
		(size 0.4572)
		(drill 0.2032)
		(layers "F.Cu" "B.Cu")
		(net "GND")
	)
	(via
		(at 428.018194 -4.95173)
		(size 0.508)
		(drill 0.254)
		(layers "F.Cu" "B.Cu")
		(net "GND")
	)
	(via
		(at 311.882282 -278.916638)
		(size 0.4572)
		(drill 0.2032)
		(layers "F.Cu" "B.Cu")
		(net "GND")
	)
	(via
		(at 420.736014 -208.366614)
		(size 0.4572)
		(drill 0.2032)
		(layers "F.Cu" "B.Cu")
		(net "GND")
	)
	(via
		(at 413.192214 -317.166752)
		(size 0.4572)
		(drill 0.2032)
		(layers "F.Cu" "B.Cu")
		(net "GND")
	)
	(via
		(at 424.836082 -228.766624)
		(size 0.4572)
		(drill 0.2032)
		(layers "F.Cu" "B.Cu")
		(net "GND")
	)
	(via
		(at 187.883546 -223.666558)
		(size 0.4572)
		(drill 0.2032)
		(layers "F.Cu" "B.Cu")
		(net "GND")
	)
	(via
		(at 263.293352 -323.429376)
		(size 0.4572)
		(drill 0.2032)
		(layers "F.Cu" "B.Cu")
		(net "GND")
	)
	(via
		(at 262.519414 -315.46673)
		(size 0.4572)
		(drill 0.2032)
		(layers "F.Cu" "B.Cu")
		(net "GND")
	)
	(via
		(at 193.47688 -71.948548)
		(size 0.508)
		(drill 0.254)
		(layers "F.Cu" "B.Cu")
		(net "GND")
	)
	(via
		(at 314.092082 -196.466714)
		(size 0.4572)
		(drill 0.2032)
		(layers "F.Cu" "B.Cu")
		(net "GND")
	)
	(via
		(at 343.431368 -335.704434)
		(size 0.49022)
		(drill 0.254)
		(layers "F.Cu" "B.Cu")
		(net "GND")
	)
	(via
		(at 16.789146 -315.46673)
		(size 0.4572)
		(drill 0.2032)
		(layers "F.Cu" "B.Cu")
		(net "GND")
	)
	(via
		(at 291.460682 -233.86669)
		(size 0.4572)
		(drill 0.2032)
		(layers "F.Cu" "B.Cu")
		(net "GND")
	)
	(via
		(at 165.447726 -407.638504)
		(size 0.4572)
		(drill 0.254)
		(layers "F.Cu" "B.Cu")
		(net "GND")
	)
	(via
		(at 31.876746 -309.51678)
		(size 0.4572)
		(drill 0.2032)
		(layers "F.Cu" "B.Cu")
		(net "GND")
	)
	(via
		(at 407.858214 -289.11677)
		(size 0.4572)
		(drill 0.2032)
		(layers "F.Cu" "B.Cu")
		(net "GND")
	)
	(via
		(at 449.677282 -221.116652)
		(size 0.4572)
		(drill 0.2032)
		(layers "F.Cu" "B.Cu")
		(net "GND")
	)
	(via
		(at 428.279814 -217.716608)
		(size 0.4572)
		(drill 0.2032)
		(layers "F.Cu" "B.Cu")
		(net "GND")
	)
	(via
		(at 378.97181 -403.883876)
		(size 0.4064)
		(drill 0.2032)
		(layers "F.Cu" "B.Cu")
		(net "GND")
	)
	(via
		(at 307.782214 -201.56678)
		(size 0.4572)
		(drill 0.2032)
		(layers "F.Cu" "B.Cu")
		(net "GND")
	)
	(via
		(at 214.615014 -219.41663)
		(size 0.4572)
		(drill 0.2032)
		(layers "F.Cu" "B.Cu")
		(net "GND")
	)
	(via
		(at 439.62828 -19.395948)
		(size 0.508)
		(drill 0.254)
		(layers "F.Cu" "B.Cu")
		(net "GND")
	)
	(via
		(at 22.897084 -323.434456)
		(size 0.4572)
		(drill 0.2032)
		(layers "F.Cu" "B.Cu")
		(net "GND")
	)
	(via
		(at 170.011598 -352.404172)
		(size 0.49022)
		(drill 0.254)
		(layers "F.Cu" "B.Cu")
		(net "GND")
	)
	(via
		(at 43.520614 -235.566712)
		(size 0.4572)
		(drill 0.2032)
		(layers "F.Cu" "B.Cu")
		(net "GND")
	)
	(via
		(at 7.035546 -223.666558)
		(size 0.4572)
		(drill 0.2032)
		(layers "F.Cu" "B.Cu")
		(net "GND")
	)
	(via
		(at 212.724746 -203.266802)
		(size 0.4572)
		(drill 0.2032)
		(layers "F.Cu" "B.Cu")
		(net "GND")
	)
	(via
		(at 22.123146 -261.916672)
		(size 0.4572)
		(drill 0.2032)
		(layers "F.Cu" "B.Cu")
		(net "GND")
	)
	(via
		(at 363.36605 -259.05079)
		(size 0.4572)
		(drill 0.2032)
		(layers "F.Cu" "B.Cu")
		(net "GND")
	)
	(via
		(at 180.339746 -251.716794)
		(size 0.4572)
		(drill 0.2032)
		(layers "F.Cu" "B.Cu")
		(net "GND")
	)
	(via
		(at 22.147022 -10.16508)
		(size 0.508)
		(drill 0.254)
		(layers "F.Cu" "B.Cu")
		(net "GND")
	)
	(via
		(at 287.360614 -203.266802)
		(size 0.4572)
		(drill 0.2032)
		(layers "F.Cu" "B.Cu")
		(net "GND")
	)
	(via
		(at 164.018214 -198.166736)
		(size 0.4572)
		(drill 0.2032)
		(layers "F.Cu" "B.Cu")
		(net "GND")
	)
	(via
		(at 187.883546 -244.916706)
		(size 0.4572)
		(drill 0.2032)
		(layers "F.Cu" "B.Cu")
		(net "GND")
	)
	(via
		(at 363.422692 -333.356458)
		(size 0.49022)
		(drill 0.254)
		(layers "F.Cu" "B.Cu")
		(net "GND")
	)
	(via
		(at 344.691208 -335.704434)
		(size 0.49022)
		(drill 0.254)
		(layers "F.Cu" "B.Cu")
		(net "GND")
	)
	(via
		(at 191.983614 -267.866622)
		(size 0.4572)
		(drill 0.2032)
		(layers "F.Cu" "B.Cu")
		(net "GND")
	)
	(via
		(at 216.824814 -269.566644)
		(size 0.4572)
		(drill 0.2032)
		(layers "F.Cu" "B.Cu")
		(net "GND")
	)
	(via
		(at 197.637146 -204.96657)
		(size 0.4572)
		(drill 0.2032)
		(layers "F.Cu" "B.Cu")
		(net "GND")
	)
	(via
		(at 100.832666 -246.364506)
		(size 0.4572)
		(drill 0.2032)
		(layers "F.Cu" "B.Cu")
		(net "GND")
	)
	(via
		(at 432.379882 -238.116618)
		(size 0.4572)
		(drill 0.2032)
		(layers "F.Cu" "B.Cu")
		(net "GND")
	)
	(via
		(at 48.854614 -245.76659)
		(size 0.4572)
		(drill 0.2032)
		(layers "F.Cu" "B.Cu")
		(net "GND")
	)
	(via
		(at 178.222148 -351.414588)
		(size 0.508)
		(drill 0.254)
		(layers "F.Cu" "B.Cu")
		(net "GND")
	)
	(via
		(at 171.15028 -354.115878)
		(size 0.49022)
		(drill 0.254)
		(layers "F.Cu" "B.Cu")
		(net "GND")
	)
	(via
		(at 102.821994 -287.28924)
		(size 0.4572)
		(drill 0.2032)
		(layers "F.Cu" "B.Cu")
		(net "GND")
	)
	(via
		(at 274.163282 -284.866588)
		(size 0.4572)
		(drill 0.2032)
		(layers "F.Cu" "B.Cu")
		(net "GND")
	)
	(via
		(at 413.192214 -217.716608)
		(size 0.4572)
		(drill 0.2032)
		(layers "F.Cu" "B.Cu")
		(net "GND")
	)
	(via
		(at 76.644754 -31.614364)
		(size 0.508)
		(drill 0.254)
		(layers "F.Cu" "B.Cu")
		(net "GND")
	)
	(via
		(at 243.6114 -200.624948)
		(size 0.508)
		(drill 0.254)
		(layers "F.Cu" "B.Cu")
		(net "GND")
	)
	(via
		(at 53.267102 -7.215124)
		(size 0.508)
		(drill 0.254)
		(layers "F.Cu" "B.Cu")
		(net "GND")
	)
	(via
		(at 197.637146 -313.766708)
		(size 0.4572)
		(drill 0.2032)
		(layers "F.Cu" "B.Cu")
		(net "GND")
	)
	(via
		(at 457.221082 -250.866656)
		(size 0.4572)
		(drill 0.2032)
		(layers "F.Cu" "B.Cu")
		(net "GND")
	)
	(via
		(at 157.349952 -431.29962)
		(size 0.4572)
		(drill 0.2032)
		(layers "F.Cu" "B.Cu")
		(net "GND")
	)
	(via
		(at 92.844366 -247.178322)
		(size 0.4572)
		(drill 0.2032)
		(layers "F.Cu" "B.Cu")
		(net "GND")
	)
	(via
		(at 185.16092 -10.127488)
		(size 0.508)
		(drill 0.254)
		(layers "F.Cu" "B.Cu")
		(net "GND")
	)
	(via
		(at 14.579346 -248.31675)
		(size 0.4572)
		(drill 0.2032)
		(layers "F.Cu" "B.Cu")
		(net "GND")
	)
	(via
		(at 176.901348 -351.414588)
		(size 0.508)
		(drill 0.254)
		(layers "F.Cu" "B.Cu")
		(net "GND")
	)
	(via
		(at 346.42298 -247.178322)
		(size 0.4572)
		(drill 0.2032)
		(layers "F.Cu" "B.Cu")
		(net "GND")
	)
	(via
		(at 49.170082 -16.978376)
		(size 0.508)
		(drill 0.254)
		(layers "F.Cu" "B.Cu")
		(net "GND")
	)
	(via
		(at 37.210746 -244.916706)
		(size 0.4572)
		(drill 0.2032)
		(layers "F.Cu" "B.Cu")
		(net "GND")
	)
	(via
		(at 28.433014 -306.96662)
		(size 0.4572)
		(drill 0.2032)
		(layers "F.Cu" "B.Cu")
		(net "GND")
	)
	(via
		(at 37.210746 -233.016806)
		(size 0.4572)
		(drill 0.2032)
		(layers "F.Cu" "B.Cu")
		(net "GND")
	)
	(via
		(at 149.857206 -189.35065)
		(size 0.508)
		(drill 0.254)
		(layers "F.Cu" "B.Cu")
		(net "GND")
	)
	(via
		(at 124.907294 -286.475424)
		(size 0.4572)
		(drill 0.2032)
		(layers "F.Cu" "B.Cu")
		(net "GND")
	)
	(via
		(at 340.784434 -234.15625)
		(size 0.4572)
		(drill 0.2032)
		(layers "F.Cu" "B.Cu")
		(net "GND")
	)
	(via
		(at 428.283116 -110.27664)
		(size 0.508)
		(drill 0.254)
		(layers "F.Cu" "B.Cu")
		(net "GND")
	)
	(via
		(at 154.966416 -30.312868)
		(size 0.508)
		(drill 0.254)
		(layers "F.Cu" "B.Cu")
		(net "GND")
	)
	(via
		(at 89.554812 -228.45903)
		(size 0.4572)
		(drill 0.2032)
		(layers "F.Cu" "B.Cu")
		(net "GND")
	)
	(via
		(at 132.210302 -400.224244)
		(size 0.4572)
		(drill 0.254)
		(layers "F.Cu" "B.Cu")
		(net "GND")
	)
	(via
		(at 29.666946 -233.016806)
		(size 0.4572)
		(drill 0.2032)
		(layers "F.Cu" "B.Cu")
		(net "GND")
	)
	(via
		(at 44.754546 -287.416748)
		(size 0.4572)
		(drill 0.2032)
		(layers "F.Cu" "B.Cu")
		(net "GND")
	)
	(via
		(at 346.250006 -438.499758)
		(size 0.4572)
		(drill 0.2032)
		(layers "F.Cu" "B.Cu")
		(net "GND")
	)
	(via
		(at 269.234412 -67.88785)
		(size 0.6604)
		(drill 0.3302)
		(layers "F.Cu" "B.Cu")
		(net "GND")
	)
	(via
		(at 346.250006 -428.851314)
		(size 0.4572)
		(drill 0.2032)
		(layers "F.Cu" "B.Cu")
		(net "GND")
	)
	(via
		(at 449.677282 -278.916638)
		(size 0.4572)
		(drill 0.2032)
		(layers "F.Cu" "B.Cu")
		(net "GND")
	)
	(via
		(at 97.626678 -331.776832)
		(size 0.49022)
		(drill 0.254)
		(layers "F.Cu" "B.Cu")
		(net "GND")
	)
	(via
		(at 92.954348 -270.19758)
		(size 0.4572)
		(drill 0.2032)
		(layers "F.Cu" "B.Cu")
		(net "GND")
	)
	(via
		(at 37.210746 -317.166752)
		(size 0.4572)
		(drill 0.2032)
		(layers "F.Cu" "B.Cu")
		(net "GND")
	)
	(via
		(at 403.47773 -400.858228)
		(size 0.4064)
		(drill 0.2032)
		(layers "F.Cu" "B.Cu")
		(net "GND")
	)
	(via
		(at 124.366782 -410.664152)
		(size 0.4572)
		(drill 0.254)
		(layers "F.Cu" "B.Cu")
		(net "GND")
	)
	(via
		(at 415.402014 -287.213548)
		(size 0.4572)
		(drill 0.2032)
		(layers "F.Cu" "B.Cu")
		(net "GND")
	)
	(via
		(at 201.737214 -196.466714)
		(size 0.4572)
		(drill 0.2032)
		(layers "F.Cu" "B.Cu")
		(net "GND")
	)
	(via
		(at 411.958282 -258.516628)
		(size 0.4572)
		(drill 0.2032)
		(layers "F.Cu" "B.Cu")
		(net "GND")
	)
	(via
		(at 164.188902 -410.664152)
		(size 0.4572)
		(drill 0.254)
		(layers "F.Cu" "B.Cu")
		(net "GND")
	)
	(via
		(at 373.92737 -403.883876)
		(size 0.4064)
		(drill 0.2032)
		(layers "F.Cu" "B.Cu")
		(net "GND")
	)
	(via
		(at 157.708346 -250.016772)
		(size 0.4572)
		(drill 0.2032)
		(layers "F.Cu" "B.Cu")
		(net "GND")
	)
	(via
		(at 338.824316 -409.396184)
		(size 0.4572)
		(drill 0.254)
		(layers "F.Cu" "B.Cu")
		(net "GND")
	)
	(via
		(at 340.250018 -435.0512)
		(size 0.4572)
		(drill 0.2032)
		(layers "F.Cu" "B.Cu")
		(net "GND")
	)
	(via
		(at 409.748482 -194.766692)
		(size 0.4572)
		(drill 0.2032)
		(layers "F.Cu" "B.Cu")
		(net "GND")
	)
	(via
		(at 273.88058 -23.739348)
		(size 0.508)
		(drill 0.254)
		(layers "F.Cu" "B.Cu")
		(net "GND")
	)
	(via
		(at 412.18358 -167.731948)
		(size 0.508)
		(drill 0.254)
		(layers "F.Cu" "B.Cu")
		(net "GND")
	)
	(via
		(at 201.8284 -91.5924)
		(size 0.508)
		(drill 0.254)
		(layers "F.Cu" "B.Cu")
		(net "GND")
	)
	(via
		(at 376.214386 -351.720658)
		(size 0.508)
		(drill 0.254)
		(layers "F.Cu" "B.Cu")
		(net "GND")
	)
	(via
		(at 294.904414 -268.71676)
		(size 0.4572)
		(drill 0.2032)
		(layers "F.Cu" "B.Cu")
		(net "GND")
	)
	(via
		(at 405.64689 -12.37488)
		(size 0.508)
		(drill 0.254)
		(layers "F.Cu" "B.Cu")
		(net "GND")
	)
	(via
		(at 132.895594 -266.128246)
		(size 0.4572)
		(drill 0.2032)
		(layers "F.Cu" "B.Cu")
		(net "GND")
	)
	(via
		(at 216.824814 -291.666676)
		(size 0.4572)
		(drill 0.2032)
		(layers "F.Cu" "B.Cu")
		(net "GND")
	)
	(via
		(at 134.35965 -347.909896)
		(size 0.508)
		(drill 0.254)
		(layers "F.Cu" "B.Cu")
		(net "GND")
	)
	(via
		(at 369.931442 -53.177948)
		(size 0.508)
		(drill 0.254)
		(layers "F.Cu" "B.Cu")
		(net "GND")
	)
	(via
		(at 462.555082 -213.46668)
		(size 0.4572)
		(drill 0.2032)
		(layers "F.Cu" "B.Cu")
		(net "GND")
	)
	(via
		(at 130.076194 -272.639282)
		(size 0.4572)
		(drill 0.2032)
		(layers "F.Cu" "B.Cu")
		(net "GND")
	)
	(via
		(at 95.663766 -216.25052)
		(size 0.4572)
		(drill 0.2032)
		(layers "F.Cu" "B.Cu")
		(net "GND")
	)
	(via
		(at 195.427346 -278.066754)
		(size 0.4572)
		(drill 0.2032)
		(layers "F.Cu" "B.Cu")
		(net "GND")
	)
	(via
		(at 458.455014 -296.766742)
		(size 0.4572)
		(drill 0.2032)
		(layers "F.Cu" "B.Cu")
		(net "GND")
	)
	(via
		(at 311.882282 -305.266598)
		(size 0.4572)
		(drill 0.2032)
		(layers "F.Cu" "B.Cu")
		(net "GND")
	)
	(via
		(at 340.784434 -240.667286)
		(size 0.4572)
		(drill 0.2032)
		(layers "F.Cu" "B.Cu")
		(net "GND")
	)
	(via
		(at 192.721484 -323.434456)
		(size 0.4572)
		(drill 0.2032)
		(layers "F.Cu" "B.Cu")
		(net "GND")
	)
	(via
		(at 199.527414 -264.466578)
		(size 0.4572)
		(drill 0.2032)
		(layers "F.Cu" "B.Cu")
		(net "GND")
	)
	(via
		(at 432.379882 -239.81664)
		(size 0.4572)
		(drill 0.2032)
		(layers "F.Cu" "B.Cu")
		(net "GND")
	)
	(via
		(at 315.250068 -438.651396)
		(size 0.4572)
		(drill 0.2032)
		(layers "F.Cu" "B.Cu")
		(net "GND")
	)
	(via
		(at 300.022514 -313.766708)
		(size 0.4572)
		(drill 0.2032)
		(layers "F.Cu" "B.Cu")
		(net "GND")
	)
	(via
		(at 87.226394 -92.238322)
		(size 0.508)
		(drill 0.254)
		(layers "F.Cu" "B.Cu")
		(net "GND")
	)
	(via
		(at 88.615012 -249.620024)
		(size 0.4572)
		(drill 0.2032)
		(layers "F.Cu" "B.Cu")
		(net "GND")
	)
	(via
		(at 409.349956 -426.54728)
		(size 0.4572)
		(drill 0.2032)
		(layers "F.Cu" "B.Cu")
		(net "GND")
	)
	(via
		(at 253.15545 -326.89419)
		(size 0.508)
		(drill 0.254)
		(layers "F.Cu" "B.Cu")
		(net "GND")
	)
	(via
		(at 345.013534 -217.064336)
		(size 0.4572)
		(drill 0.2032)
		(layers "F.Cu" "B.Cu")
		(net "GND")
	)
	(via
		(at 106.941366 -222.761556)
		(size 0.4572)
		(drill 0.2032)
		(layers "F.Cu" "B.Cu")
		(net "GND")
	)
	(via
		(at 135.263382 -76.073)
		(size 0.508)
		(drill 0.254)
		(layers "F.Cu" "B.Cu")
		(net "GND")
	)
	(via
		(at 419.932866 -358.754172)
		(size 0.508)
		(drill 0.254)
		(layers "F.Cu" "B.Cu")
		(net "GND")
	)
	(via
		(at 14.579346 -242.3668)
		(size 0.4572)
		(drill 0.2032)
		(layers "F.Cu" "B.Cu")
		(net "GND")
	)
	(via
		(at 384.649726 -78.350618)
		(size 0.508)
		(drill 0.254)
		(layers "F.Cu" "B.Cu")
		(net "GND")
	)
	(via
		(at 85.435694 -283.219906)
		(size 0.4572)
		(drill 0.2032)
		(layers "F.Cu" "B.Cu")
		(net "GND")
	)
	(via
		(at 166.737284 -323.434456)
		(size 0.4572)
		(drill 0.2032)
		(layers "F.Cu" "B.Cu")
		(net "GND")
	)
	(via
		(at 194.82943 -24.37384)
		(size 0.508)
		(drill 0.254)
		(layers "F.Cu" "B.Cu")
		(net "GND")
	)
	(via
		(at 407.34996 -438.651396)
		(size 0.4572)
		(drill 0.2032)
		(layers "F.Cu" "B.Cu")
		(net "GND")
	)
	(via
		(at 340.894416 -263.686544)
		(size 0.4572)
		(drill 0.2032)
		(layers "F.Cu" "B.Cu")
		(net "GND")
	)
	(via
		(at 299.004482 -211.766658)
		(size 0.4572)
		(drill 0.2032)
		(layers "F.Cu" "B.Cu")
		(net "GND")
	)
	(via
		(at 458.455014 -268.71676)
		(size 0.4572)
		(drill 0.2032)
		(layers "F.Cu" "B.Cu")
		(net "GND")
	)
	(via
		(at 59.385962 -151.59228)
		(size 0.508)
		(drill 0.254)
		(layers "F.Cu" "B.Cu")
		(net "GND")
	)
	(via
		(at 334.205834 -237.411768)
		(size 0.4572)
		(drill 0.2032)
		(layers "F.Cu" "B.Cu")
		(net "GND")
	)
	(via
		(at 31.876746 -283.166566)
		(size 0.4572)
		(drill 0.2032)
		(layers "F.Cu" "B.Cu")
		(net "GND")
	)
	(via
		(at 305.0413 -400.224244)
		(size 0.4572)
		(drill 0.254)
		(layers "F.Cu" "B.Cu")
		(net "GND")
	)
	(via
		(at 329.000612 -75.452224)
		(size 0.508)
		(drill 0.254)
		(layers "F.Cu" "B.Cu")
		(net "GND")
	)
	(via
		(at 421.15359 -179.707794)
		(size 0.508)
		(drill 0.254)
		(layers "F.Cu" "B.Cu")
		(net "GND")
	)
	(via
		(at 297.843702 -423.954448)
		(size 0.508)
		(drill 0.254)
		(layers "F.Cu" "B.Cu")
		(net "GND")
	)
	(via
		(at 327.250044 -433.899564)
		(size 0.4572)
		(drill 0.2032)
		(layers "F.Cu" "B.Cu")
		(net "GND")
	)
	(via
		(at 415.402014 -317.166752)
		(size 0.4572)
		(drill 0.2032)
		(layers "F.Cu" "B.Cu")
		(net "GND")
	)
	(via
		(at 425.997624 -19.125438)
		(size 0.508)
		(drill 0.254)
		(layers "F.Cu" "B.Cu")
		(net "GND")
	)
	(via
		(at 43.520614 -204.116686)
		(size 0.4572)
		(drill 0.2032)
		(layers "F.Cu" "B.Cu")
		(net "GND")
	)
	(via
		(at 283.863796 -367.945416)
		(size 0.508)
		(drill 0.254)
		(layers "F.Cu" "B.Cu")
		(net "GND")
	)
	(via
		(at 450.911214 -272.116804)
		(size 0.4572)
		(drill 0.2032)
		(layers "F.Cu" "B.Cu")
		(net "GND")
	)
	(via
		(at 349.367602 -326.910192)
		(size 0.508)
		(drill 0.254)
		(layers "F.Cu" "B.Cu")
		(net "GND")
	)
	(via
		(at 411.197552 -323.429376)
		(size 0.4572)
		(drill 0.2032)
		(layers "F.Cu" "B.Cu")
		(net "GND")
	)
	(via
		(at 370.497862 -254.733552)
		(size 0.4572)
		(drill 0.2032)
		(layers "F.Cu" "B.Cu")
		(net "GND")
	)
	(via
		(at 430.272698 -59.226196)
		(size 0.508)
		(drill 0.254)
		(layers "F.Cu" "B.Cu")
		(net "GND")
	)
	(via
		(at 90.604848 -262.872474)
		(size 0.4572)
		(drill 0.2032)
		(layers "F.Cu" "B.Cu")
		(net "GND")
	)
	(via
		(at 95.491554 -334.282034)
		(size 0.49022)
		(drill 0.254)
		(layers "F.Cu" "B.Cu")
		(net "GND")
	)
	(via
		(at 348.412816 -265.314176)
		(size 0.4572)
		(drill 0.2032)
		(layers "F.Cu" "B.Cu")
		(net "GND")
	)
	(via
		(at 113.989866 -223.575626)
		(size 0.4572)
		(drill 0.2032)
		(layers "F.Cu" "B.Cu")
		(net "GND")
	)
	(via
		(at 335.145126 -217.878406)
		(size 0.4572)
		(drill 0.2032)
		(layers "F.Cu" "B.Cu")
		(net "GND")
	)
	(via
		(at 83.70189 -12.544552)
		(size 0.508)
		(drill 0.254)
		(layers "F.Cu" "B.Cu")
		(net "GND")
	)
	(via
		(at 462.555082 -215.166702)
		(size 0.4572)
		(drill 0.2032)
		(layers "F.Cu" "B.Cu")
		(net "GND")
	)
	(via
		(at 464.764882 -282.316682)
		(size 0.4572)
		(drill 0.2032)
		(layers "F.Cu" "B.Cu")
		(net "GND")
	)
	(via
		(at 63.726314 -282.316682)
		(size 0.4572)
		(drill 0.2032)
		(layers "F.Cu" "B.Cu")
		(net "GND")
	)
	(via
		(at 136.184894 -276.708616)
		(size 0.4572)
		(drill 0.2032)
		(layers "F.Cu" "B.Cu")
		(net "GND")
	)
	(via
		(at 176.896014 -288.266632)
		(size 0.4572)
		(drill 0.2032)
		(layers "F.Cu" "B.Cu")
		(net "GND")
	)
	(via
		(at 94.254066 -231.714548)
		(size 0.4572)
		(drill 0.2032)
		(layers "F.Cu" "B.Cu")
		(net "GND")
	)
	(via
		(at 58.608214 -262.76681)
		(size 0.4572)
		(drill 0.2032)
		(layers "F.Cu" "B.Cu")
		(net "GND")
	)
	(via
		(at 56.834786 -158.66745)
		(size 0.49022)
		(drill 0.254)
		(layers "F.Cu" "B.Cu")
		(net "GND")
	)
	(via
		(at 365.219234 -226.017328)
		(size 0.4572)
		(drill 0.2032)
		(layers "F.Cu" "B.Cu")
		(net "GND")
	)
	(via
		(at 464.938364 -408.091132)
		(size 0.508)
		(drill 0.254)
		(layers "F.Cu" "B.Cu")
		(net "GND")
	)
	(via
		(at 120.45188 -145.486628)
		(size 0.508)
		(drill 0.254)
		(layers "F.Cu" "B.Cu")
		(net "GND")
	)
	(via
		(at 380.72568 -231.714548)
		(size 0.4572)
		(drill 0.2032)
		(layers "F.Cu" "B.Cu")
		(net "GND")
	)
	(via
		(at 44.754546 -281.466798)
		(size 0.4572)
		(drill 0.2032)
		(layers "F.Cu" "B.Cu")
		(net "GND")
	)
	(via
		(at 395.431772 -18.235422)
		(size 0.508)
		(drill 0.254)
		(layers "F.Cu" "B.Cu")
		(net "GND")
	)
	(via
		(at 180.155596 -121.375424)
		(size 0.4572)
		(drill 0.254)
		(layers "F.Cu" "B.Cu")
		(net "GND")
	)
	(via
		(at 2.764536 -396.670022)
		(size 0.508)
		(drill 0.254)
		(layers "F.Cu" "B.Cu")
		(net "GND")
	)
	(via
		(at 189.28588 -134.711948)
		(size 0.508)
		(drill 0.254)
		(layers "F.Cu" "B.Cu")
		(net "GND")
	)
	(via
		(at 169.352214 -196.466714)
		(size 0.4572)
		(drill 0.2032)
		(layers "F.Cu" "B.Cu")
		(net "GND")
	)
	(via
		(at 375.087134 -226.831144)
		(size 0.4572)
		(drill 0.2032)
		(layers "F.Cu" "B.Cu")
		(net "GND")
	)
	(via
		(at 409.748482 -278.916638)
		(size 0.4572)
		(drill 0.2032)
		(layers "F.Cu" "B.Cu")
		(net "GND")
	)
	(via
		(at 98.592894 -255.547622)
		(size 0.4572)
		(drill 0.2032)
		(layers "F.Cu" "B.Cu")
		(net "GND")
	)
	(via
		(at 54.508146 -206.666592)
		(size 0.4572)
		(drill 0.2032)
		(layers "F.Cu" "B.Cu")
		(net "GND")
	)
	(via
		(at 48.854614 -215.166702)
		(size 0.4572)
		(drill 0.2032)
		(layers "F.Cu" "B.Cu")
		(net "GND")
	)
	(via
		(at 110.96752 -412.100268)
		(size 0.508)
		(drill 0.254)
		(layers "F.Cu" "B.Cu")
		(net "GND")
	)
	(via
		(at 159.918146 -220.266768)
		(size 0.4572)
		(drill 0.2032)
		(layers "F.Cu" "B.Cu")
		(net "GND")
	)
	(via
		(at 28.433014 -284.866588)
		(size 0.4572)
		(drill 0.2032)
		(layers "F.Cu" "B.Cu")
		(net "GND")
	)
	(via
		(at 417.289742 -153.468324)
		(size 0.508)
		(drill 0.254)
		(layers "F.Cu" "B.Cu")
		(net "GND")
	)
	(via
		(at 78.053438 -403.883876)
		(size 0.4064)
		(drill 0.2032)
		(layers "F.Cu" "B.Cu")
		(net "GND")
	)
	(via
		(at 428.279814 -283.166566)
		(size 0.4572)
		(drill 0.2032)
		(layers "F.Cu" "B.Cu")
		(net "GND")
	)
	(via
		(at 191.983614 -314.616592)
		(size 0.4572)
		(drill 0.2032)
		(layers "F.Cu" "B.Cu")
		(net "GND")
	)
	(via
		(at 179.105814 -238.116618)
		(size 0.4572)
		(drill 0.2032)
		(layers "F.Cu" "B.Cu")
		(net "GND")
	)
	(via
		(at 262.519414 -238.966756)
		(size 0.4572)
		(drill 0.2032)
		(layers "F.Cu" "B.Cu")
		(net "GND")
	)
	(via
		(at 186.649614 -303.566576)
		(size 0.4572)
		(drill 0.2032)
		(layers "F.Cu" "B.Cu")
		(net "GND")
	)
	(via
		(at 165.252146 -307.816758)
		(size 0.4572)
		(drill 0.2032)
		(layers "F.Cu" "B.Cu")
		(net "GND")
	)
	(via
		(at 453.121014 -279.766776)
		(size 0.4572)
		(drill 0.2032)
		(layers "F.Cu" "B.Cu")
		(net "GND")
	)
	(via
		(at 33.034478 -161.570162)
		(size 0.508)
		(drill 0.254)
		(layers "F.Cu" "B.Cu")
		(net "GND")
	)
	(via
		(at 24.332946 -281.466798)
		(size 0.4572)
		(drill 0.2032)
		(layers "F.Cu" "B.Cu")
		(net "GND")
	)
	(via
		(at 350.292162 -286.475424)
		(size 0.4572)
		(drill 0.2032)
		(layers "F.Cu" "B.Cu")
		(net "GND")
	)
	(via
		(at 48.854614 -216.866724)
		(size 0.4572)
		(drill 0.2032)
		(layers "F.Cu" "B.Cu")
		(net "GND")
	)
	(via
		(at 352.749612 -63.667894)
		(size 0.508)
		(drill 0.254)
		(layers "F.Cu" "B.Cu")
		(net "GND")
	)
	(via
		(at 58.608214 -278.916638)
		(size 0.4572)
		(drill 0.2032)
		(layers "F.Cu" "B.Cu")
		(net "GND")
	)
	(via
		(at 467.535514 -403.72538)
		(size 0.508)
		(drill 0.254)
		(layers "F.Cu" "B.Cu")
		(net "GND")
	)
	(via
		(at 299.004482 -216.866724)
		(size 0.4572)
		(drill 0.2032)
		(layers "F.Cu" "B.Cu")
		(net "GND")
	)
	(via
		(at 167.461946 -301.866808)
		(size 0.4572)
		(drill 0.2032)
		(layers "F.Cu" "B.Cu")
		(net "GND")
	)
	(via
		(at 157.708346 -248.31675)
		(size 0.4572)
		(drill 0.2032)
		(layers "F.Cu" "B.Cu")
		(net "GND")
	)
	(via
		(at 212.724746 -260.21665)
		(size 0.4572)
		(drill 0.2032)
		(layers "F.Cu" "B.Cu")
		(net "GND")
	)
	(via
		(at 29.306266 -19.770344)
		(size 0.508)
		(drill 0.254)
		(layers "F.Cu" "B.Cu")
		(net "GND")
	)
	(via
		(at 20.585938 -6.597396)
		(size 0.508)
		(drill 0.254)
		(layers "F.Cu" "B.Cu")
		(net "GND")
	)
	(via
		(at 392.30681 -400.858228)
		(size 0.4064)
		(drill 0.2032)
		(layers "F.Cu" "B.Cu")
		(net "GND")
	)
	(via
		(at 443.367414 -248.31675)
		(size 0.4572)
		(drill 0.2032)
		(layers "F.Cu" "B.Cu")
		(net "GND")
	)
	(via
		(at 130.436366 -247.178322)
		(size 0.4572)
		(drill 0.2032)
		(layers "F.Cu" "B.Cu")
		(net "GND")
	)
	(via
		(at 336.250026 -426.69968)
		(size 0.4572)
		(drill 0.2032)
		(layers "F.Cu" "B.Cu")
		(net "GND")
	)
	(via
		(at 416.575494 -171.698158)
		(size 0.49022)
		(drill 0.254)
		(layers "F.Cu" "B.Cu")
		(net "GND")
	)
	(via
		(at 182.549546 -206.666592)
		(size 0.4572)
		(drill 0.2032)
		(layers "F.Cu" "B.Cu")
		(net "GND")
	)
	(via
		(at 413.349948 -437.34736)
		(size 0.4572)
		(drill 0.2032)
		(layers "F.Cu" "B.Cu")
		(net "GND")
	)
	(via
		(at 392.34999 -431.29962)
		(size 0.4572)
		(drill 0.2032)
		(layers "F.Cu" "B.Cu")
		(net "GND")
	)
	(via
		(at 443.367414 -289.11677)
		(size 0.4572)
		(drill 0.2032)
		(layers "F.Cu" "B.Cu")
		(net "GND")
	)
	(via
		(at 46.970442 -319.753234)
		(size 0.4572)
		(drill 0.2032)
		(layers "F.Cu" "B.Cu")
		(net "GND")
	)
	(via
		(at 311.882282 -211.766658)
		(size 0.4572)
		(drill 0.2032)
		(layers "F.Cu" "B.Cu")
		(net "GND")
	)
	(via
		(at 133.830314 -403.883876)
		(size 0.4064)
		(drill 0.2032)
		(layers "F.Cu" "B.Cu")
		(net "GND")
	)
	(via
		(at 58.608214 -202.416664)
		(size 0.4572)
		(drill 0.2032)
		(layers "F.Cu" "B.Cu")
		(net "GND")
	)
	(via
		(at 372.377462 -264.50036)
		(size 0.4572)
		(drill 0.2032)
		(layers "F.Cu" "B.Cu")
		(net "GND")
	)
	(via
		(at 420.14013 -410.030168)
		(size 0.4064)
		(drill 0.2032)
		(layers "F.Cu" "B.Cu")
		(net "GND")
	)
	(via
		(at 428.828454 -183.428132)
		(size 0.508)
		(drill 0.254)
		(layers "F.Cu" "B.Cu")
		(net "GND")
	)
	(via
		(at 18.679414 -277.216616)
		(size 0.4572)
		(drill 0.2032)
		(layers "F.Cu" "B.Cu")
		(net "GND")
	)
	(via
		(at 54.508146 -197.316598)
		(size 0.4572)
		(drill 0.2032)
		(layers "F.Cu" "B.Cu")
		(net "GND")
	)
	(via
		(at 190.093346 -233.016806)
		(size 0.4572)
		(drill 0.2032)
		(layers "F.Cu" "B.Cu")
		(net "GND")
	)
	(via
		(at 141.367002 -338.510372)
		(size 0.508)
		(drill 0.254)
		(layers "F.Cu" "B.Cu")
		(net "GND")
	)
	(via
		(at 129.608326 -335.187036)
		(size 0.49022)
		(drill 0.254)
		(layers "F.Cu" "B.Cu")
		(net "GND")
	)
	(via
		(at 340.894416 -260.430772)
		(size 0.4572)
		(drill 0.2032)
		(layers "F.Cu" "B.Cu")
		(net "GND")
	)
	(via
		(at 340.894416 -266.941808)
		(size 0.4572)
		(drill 0.2032)
		(layers "F.Cu" "B.Cu")
		(net "GND")
	)
	(via
		(at 136.075166 -234.15625)
		(size 0.4572)
		(drill 0.2032)
		(layers "F.Cu" "B.Cu")
		(net "GND")
	)
	(via
		(at 40.873172 -352.397822)
		(size 0.49022)
		(drill 0.254)
		(layers "F.Cu" "B.Cu")
		(net "GND")
	)
	(via
		(at 427.045882 -216.866724)
		(size 0.4572)
		(drill 0.2032)
		(layers "F.Cu" "B.Cu")
		(net "GND")
	)
	(via
		(at 411.52318 -159.095948)
		(size 0.508)
		(drill 0.254)
		(layers "F.Cu" "B.Cu")
		(net "GND")
	)
	(via
		(at 137.124948 -255.547368)
		(size 0.4318)
		(drill 0.2032)
		(layers "F.Cu" "B.Cu")
		(net "GND")
	)
	(via
		(at 164.018214 -210.066636)
		(size 0.4572)
		(drill 0.2032)
		(layers "F.Cu" "B.Cu")
		(net "GND")
	)
	(via
		(at 41.310814 -316.316614)
		(size 0.4572)
		(drill 0.2032)
		(layers "F.Cu" "B.Cu")
		(net "GND")
	)
	(via
		(at 340.305136 -332.512924)
		(size 0.508)
		(drill 0.254)
		(layers "F.Cu" "B.Cu")
		(net "GND")
	)
	(via
		(at 133.365748 -283.219906)
		(size 0.4572)
		(drill 0.2032)
		(layers "F.Cu" "B.Cu")
		(net "GND")
	)
	(via
		(at 186.649614 -291.666676)
		(size 0.4572)
		(drill 0.2032)
		(layers "F.Cu" "B.Cu")
		(net "GND")
	)
	(via
		(at 411.958282 -284.866588)
		(size 0.4572)
		(drill 0.2032)
		(layers "F.Cu" "B.Cu")
		(net "GND")
	)
	(via
		(at 271.200372 -72.5424)
		(size 0.508)
		(drill 0.254)
		(layers "F.Cu" "B.Cu")
		(net "GND")
	)
	(via
		(at 182.549546 -309.51678)
		(size 0.4572)
		(drill 0.2032)
		(layers "F.Cu" "B.Cu")
		(net "GND")
	)
	(via
		(at 209.281014 -238.116618)
		(size 0.4572)
		(drill 0.2032)
		(layers "F.Cu" "B.Cu")
		(net "GND")
	)
	(via
		(at 329.273408 -410.030168)
		(size 0.4064)
		(drill 0.2032)
		(layers "F.Cu" "B.Cu")
		(net "GND")
	)
	(via
		(at 378.846334 -226.831144)
		(size 0.4572)
		(drill 0.2032)
		(layers "F.Cu" "B.Cu")
		(net "GND")
	)
	(via
		(at 347.92666 -400.200368)
		(size 0.4572)
		(drill 0.254)
		(layers "F.Cu" "B.Cu")
		(net "GND")
	)
	(via
		(at 47.21733 -394.43025)
		(size 0.508)
		(drill 0.254)
		(layers "F.Cu" "B.Cu")
		(net "GND")
	)
	(via
		(at 336.665316 -272.639282)
		(size 0.4572)
		(drill 0.2032)
		(layers "F.Cu" "B.Cu")
		(net "GND")
	)
	(via
		(at 311.882282 -301.01667)
		(size 0.4572)
		(drill 0.2032)
		(layers "F.Cu" "B.Cu")
		(net "GND")
	)
	(via
		(at 462.555082 -288.266632)
		(size 0.4572)
		(drill 0.2032)
		(layers "F.Cu" "B.Cu")
		(net "GND")
	)
	(via
		(at 386.604764 -333.453232)
		(size 0.508)
		(drill 0.254)
		(layers "F.Cu" "B.Cu")
		(net "GND")
	)
	(via
		(at 201.737214 -215.166702)
		(size 0.4572)
		(drill 0.2032)
		(layers "F.Cu" "B.Cu")
		(net "GND")
	)
	(via
		(at 462.555082 -258.516628)
		(size 0.4572)
		(drill 0.2032)
		(layers "F.Cu" "B.Cu")
		(net "GND")
	)
	(via
		(at 177.09388 -102.707948)
		(size 0.508)
		(drill 0.254)
		(layers "F.Cu" "B.Cu")
		(net "GND")
	)
	(via
		(at 175.005746 -278.066754)
		(size 0.4572)
		(drill 0.2032)
		(layers "F.Cu" "B.Cu")
		(net "GND")
	)
	(via
		(at 194.193414 -278.916638)
		(size 0.4572)
		(drill 0.2032)
		(layers "F.Cu" "B.Cu")
		(net "GND")
	)
	(via
		(at 16.789146 -292.516814)
		(size 0.4572)
		(drill 0.2032)
		(layers "F.Cu" "B.Cu")
		(net "GND")
	)
	(via
		(at 235.42752 -387.37794)
		(size 0.508)
		(drill 0.254)
		(layers "F.Cu" "B.Cu")
		(net "GND")
	)
	(via
		(at 124.437394 -264.50036)
		(size 0.4572)
		(drill 0.2032)
		(layers "F.Cu" "B.Cu")
		(net "GND")
	)
	(via
		(at 471.03538 -53.944266)
		(size 0.508)
		(drill 0.254)
		(layers "F.Cu" "B.Cu")
		(net "GND")
	)
	(via
		(at 41.310814 -261.066788)
		(size 0.4572)
		(drill 0.2032)
		(layers "F.Cu" "B.Cu")
		(net "GND")
	)
	(via
		(at 103.761794 -287.28924)
		(size 0.4572)
		(drill 0.2032)
		(layers "F.Cu" "B.Cu")
		(net "GND")
	)
	(via
		(at 428.279814 -229.616762)
		(size 0.4572)
		(drill 0.2032)
		(layers "F.Cu" "B.Cu")
		(net "GND")
	)
	(via
		(at 339.253322 -137.172192)
		(size 0.508)
		(drill 0.254)
		(layers "F.Cu" "B.Cu")
		(net "GND")
	)
	(via
		(at 26.223214 -277.216616)
		(size 0.4572)
		(drill 0.2032)
		(layers "F.Cu" "B.Cu")
		(net "GND")
	)
	(via
		(at 205.180946 -260.21665)
		(size 0.4572)
		(drill 0.2032)
		(layers "F.Cu" "B.Cu")
		(net "GND")
	)
	(via
		(at 190.093346 -197.316598)
		(size 0.4572)
		(drill 0.2032)
		(layers "F.Cu" "B.Cu")
		(net "GND")
	)
	(via
		(at 289.250882 -250.866656)
		(size 0.4572)
		(drill 0.2032)
		(layers "F.Cu" "B.Cu")
		(net "GND")
	)
	(via
		(at 299.821092 -73.612756)
		(size 0.508)
		(drill 0.254)
		(layers "F.Cu" "B.Cu")
		(net "GND")
	)
	(via
		(at 56.398414 -267.866622)
		(size 0.4572)
		(drill 0.2032)
		(layers "F.Cu" "B.Cu")
		(net "GND")
	)
	(via
		(at 455.011282 -219.41663)
		(size 0.4572)
		(drill 0.2032)
		(layers "F.Cu" "B.Cu")
		(net "GND")
	)
	(via
		(at 366.659414 -263.376156)
		(size 0.4572)
		(drill 0.2032)
		(layers "F.Cu" "B.Cu")
		(net "GND")
	)
	(via
		(at 372.377462 -284.033722)
		(size 0.4572)
		(drill 0.2032)
		(layers "F.Cu" "B.Cu")
		(net "GND")
	)
	(via
		(at 180.339746 -248.31675)
		(size 0.4572)
		(drill 0.2032)
		(layers "F.Cu" "B.Cu")
		(net "GND")
	)
	(via
		(at 292.694614 -240.666778)
		(size 0.4572)
		(drill 0.2032)
		(layers "F.Cu" "B.Cu")
		(net "GND")
	)
	(via
		(at 420.4081 -4.95173)
		(size 0.508)
		(drill 0.254)
		(layers "F.Cu" "B.Cu")
		(net "GND")
	)
	(via
		(at 168.082722 -132.376164)
		(size 0.508)
		(drill 0.254)
		(layers "F.Cu" "B.Cu")
		(net "GND")
	)
	(via
		(at 111.966502 -331.776832)
		(size 0.49022)
		(drill 0.254)
		(layers "F.Cu" "B.Cu")
		(net "GND")
	)
	(via
		(at 389.146542 -409.396184)
		(size 0.4572)
		(drill 0.254)
		(layers "F.Cu" "B.Cu")
		(net "GND")
	)
	(via
		(at 309.992014 -223.666558)
		(size 0.4572)
		(drill 0.2032)
		(layers "F.Cu" "B.Cu")
		(net "GND")
	)
	(via
		(at 175.005746 -260.21665)
		(size 0.4572)
		(drill 0.2032)
		(layers "F.Cu" "B.Cu")
		(net "GND")
	)
	(via
		(at 457.221082 -258.516628)
		(size 0.4572)
		(drill 0.2032)
		(layers "F.Cu" "B.Cu")
		(net "GND")
	)
	(via
		(at 287.564068 -395.046454)
		(size 0.508)
		(drill 0.254)
		(layers "F.Cu" "B.Cu")
		(net "GND")
	)
	(via
		(at 100.832412 -247.992138)
		(size 0.4572)
		(drill 0.2032)
		(layers "F.Cu" "B.Cu")
		(net "GND")
	)
	(via
		(at 165.252146 -233.016806)
		(size 0.4572)
		(drill 0.2032)
		(layers "F.Cu" "B.Cu")
		(net "GND")
	)
	(via
		(at 345.48318 -245.55069)
		(size 0.4572)
		(drill 0.2032)
		(layers "F.Cu" "B.Cu")
		(net "GND")
	)
	(via
		(at 294.904414 -201.56678)
		(size 0.4572)
		(drill 0.2032)
		(layers "F.Cu" "B.Cu")
		(net "GND")
	)
	(via
		(at 392.637772 -18.491454)
		(size 0.508)
		(drill 0.254)
		(layers "F.Cu" "B.Cu")
		(net "GND")
	)
	(via
		(at 338.250022 -436.051198)
		(size 0.4572)
		(drill 0.2032)
		(layers "F.Cu" "B.Cu")
		(net "GND")
	)
	(via
		(at 445.577214 -210.916774)
		(size 0.4572)
		(drill 0.2032)
		(layers "F.Cu" "B.Cu")
		(net "GND")
	)
	(via
		(at 338.544916 -282.405836)
		(size 0.4572)
		(drill 0.2032)
		(layers "F.Cu" "B.Cu")
		(net "GND")
	)
	(via
		(at 336.195162 -276.708616)
		(size 0.4572)
		(drill 0.2032)
		(layers "F.Cu" "B.Cu")
		(net "GND")
	)
	(via
		(at 102.4128 -145.445988)
		(size 0.508)
		(drill 0.254)
		(layers "F.Cu" "B.Cu")
		(net "GND")
	)
	(via
		(at 434.589682 -228.766624)
		(size 0.4572)
		(drill 0.2032)
		(layers "F.Cu" "B.Cu")
		(net "GND")
	)
	(via
		(at 235.25861 -117.155976)
		(size 0.508)
		(drill 0.254)
		(layers "F.Cu" "B.Cu")
		(net "GND")
	)
	(via
		(at 356.761034 -226.017328)
		(size 0.4572)
		(drill 0.2032)
		(layers "F.Cu" "B.Cu")
		(net "GND")
	)
	(via
		(at 179.105814 -207.51673)
		(size 0.4572)
		(drill 0.2032)
		(layers "F.Cu" "B.Cu")
		(net "GND")
	)
	(via
		(at 398.223232 -4.95173)
		(size 0.508)
		(drill 0.254)
		(layers "F.Cu" "B.Cu")
		(net "GND")
	)
	(via
		(at 37.210746 -289.11677)
		(size 0.4572)
		(drill 0.2032)
		(layers "F.Cu" "B.Cu")
		(net "GND")
	)
	(via
		(at 44.754546 -221.96679)
		(size 0.4572)
		(drill 0.2032)
		(layers "F.Cu" "B.Cu")
		(net "GND")
	)
	(via
		(at 370.388134 -241.481102)
		(size 0.4572)
		(drill 0.2032)
		(layers "F.Cu" "B.Cu")
		(net "GND")
	)
	(via
		(at 435.48808 -9.439148)
		(size 0.508)
		(drill 0.254)
		(layers "F.Cu" "B.Cu")
		(net "GND")
	)
	(via
		(at 2.764536 -401.750022)
		(size 0.508)
		(drill 0.254)
		(layers "F.Cu" "B.Cu")
		(net "GND")
	)
	(via
		(at 291.460682 -305.266598)
		(size 0.4572)
		(drill 0.2032)
		(layers "F.Cu" "B.Cu")
		(net "GND")
	)
	(via
		(at 354.991416 -281.59202)
		(size 0.4572)
		(drill 0.2032)
		(layers "F.Cu" "B.Cu")
		(net "GND")
	)
	(via
		(at 182.549546 -203.266802)
		(size 0.4572)
		(drill 0.2032)
		(layers "F.Cu" "B.Cu")
		(net "GND")
	)
	(via
		(at 48.854614 -282.316682)
		(size 0.4572)
		(drill 0.2032)
		(layers "F.Cu" "B.Cu")
		(net "GND")
	)
	(via
		(at 127.616966 -230.900478)
		(size 0.4572)
		(drill 0.2032)
		(layers "F.Cu" "B.Cu")
		(net "GND")
	)
	(via
		(at 159.918146 -279.766776)
		(size 0.4572)
		(drill 0.2032)
		(layers "F.Cu" "B.Cu")
		(net "GND")
	)
	(via
		(at 387.52653 -407.00452)
		(size 0.4064)
		(drill 0.2032)
		(layers "F.Cu" "B.Cu")
		(net "GND")
	)
	(via
		(at 315.250068 -427.851316)
		(size 0.4572)
		(drill 0.2032)
		(layers "F.Cu" "B.Cu")
		(net "GND")
	)
	(via
		(at 28.433014 -299.316648)
		(size 0.4572)
		(drill 0.2032)
		(layers "F.Cu" "B.Cu")
		(net "GND")
	)
	(via
		(at 458.455014 -317.166752)
		(size 0.4572)
		(drill 0.2032)
		(layers "F.Cu" "B.Cu")
		(net "GND")
	)
	(via
		(at 104.701594 -279.150318)
		(size 0.4572)
		(drill 0.2032)
		(layers "F.Cu" "B.Cu")
		(net "GND")
	)
	(via
		(at 268.829282 -238.116618)
		(size 0.4572)
		(drill 0.2032)
		(layers "F.Cu" "B.Cu")
		(net "GND")
	)
	(via
		(at 7.035546 -210.916774)
		(size 0.4572)
		(drill 0.2032)
		(layers "F.Cu" "B.Cu")
		(net "GND")
	)
	(via
		(at 25.48255 -5.596636)
		(size 0.508)
		(drill 0.254)
		(layers "F.Cu" "B.Cu")
		(net "GND")
	)
	(via
		(at 382.35001 -431.451258)
		(size 0.4572)
		(drill 0.2032)
		(layers "F.Cu" "B.Cu")
		(net "GND")
	)
	(via
		(at 99.422966 -245.55069)
		(size 0.4572)
		(drill 0.2032)
		(layers "F.Cu" "B.Cu")
		(net "GND")
	)
	(via
		(at 334.67548 -230.086662)
		(size 0.4318)
		(drill 0.2032)
		(layers "F.Cu" "B.Cu")
		(net "GND")
	)
	(via
		(at 327.140824 -343.542874)
		(size 0.49022)
		(drill 0.254)
		(layers "F.Cu" "B.Cu")
		(net "GND")
	)
	(via
		(at 296.794682 -288.266632)
		(size 0.4572)
		(drill 0.2032)
		(layers "F.Cu" "B.Cu")
		(net "GND")
	)
	(via
		(at 16.789146 -246.616728)
		(size 0.4572)
		(drill 0.2032)
		(layers "F.Cu" "B.Cu")
		(net "GND")
	)
	(via
		(at 386.44449 -410.030168)
		(size 0.4064)
		(drill 0.2032)
		(layers "F.Cu" "B.Cu")
		(net "GND")
	)
	(via
		(at 317.250064 -434.899562)
		(size 0.4572)
		(drill 0.2032)
		(layers "F.Cu" "B.Cu")
		(net "GND")
	)
	(via
		(at 29.869638 -124.062236)
		(size 0.508)
		(drill 0.254)
		(layers "F.Cu" "B.Cu")
		(net "GND")
	)
	(via
		(at 344.543634 -219.506038)
		(size 0.4572)
		(drill 0.2032)
		(layers "F.Cu" "B.Cu")
		(net "GND")
	)
	(via
		(at 130.350006 -425.547282)
		(size 0.4572)
		(drill 0.2032)
		(layers "F.Cu" "B.Cu")
		(net "GND")
	)
	(via
		(at 281.707082 -308.666642)
		(size 0.4572)
		(drill 0.2032)
		(layers "F.Cu" "B.Cu")
		(net "GND")
	)
	(via
		(at 346.250006 -430.147222)
		(size 0.4572)
		(drill 0.2032)
		(layers "F.Cu" "B.Cu")
		(net "GND")
	)
	(via
		(at 420.736014 -251.716794)
		(size 0.4572)
		(drill 0.2032)
		(layers "F.Cu" "B.Cu")
		(net "GND")
	)
	(via
		(at 291.460682 -310.366664)
		(size 0.4572)
		(drill 0.2032)
		(layers "F.Cu" "B.Cu")
		(net "GND")
	)
	(via
		(at 92.844366 -219.506038)
		(size 0.4572)
		(drill 0.2032)
		(layers "F.Cu" "B.Cu")
		(net "GND")
	)
	(via
		(at 126.083822 -403.249892)
		(size 0.4572)
		(drill 0.254)
		(layers "F.Cu" "B.Cu")
		(net "GND")
	)
	(via
		(at 443.367414 -268.71676)
		(size 0.4572)
		(drill 0.2032)
		(layers "F.Cu" "B.Cu")
		(net "GND")
	)
	(via
		(at 181.02072 -351.614994)
		(size 0.49022)
		(drill 0.254)
		(layers "F.Cu" "B.Cu")
		(net "GND")
	)
	(via
		(at 386.474462 -282.405836)
		(size 0.4572)
		(drill 0.2032)
		(layers "F.Cu" "B.Cu")
		(net "GND")
	)
	(via
		(at 438.033414 -227.066602)
		(size 0.4572)
		(drill 0.2032)
		(layers "F.Cu" "B.Cu")
		(net "GND")
	)
	(via
		(at 427.045882 -308.666642)
		(size 0.4572)
		(drill 0.2032)
		(layers "F.Cu" "B.Cu")
		(net "GND")
	)
	(via
		(at 460.664814 -225.36658)
		(size 0.4572)
		(drill 0.2032)
		(layers "F.Cu" "B.Cu")
		(net "GND")
	)
	(via
		(at 26.223214 -249.166634)
		(size 0.4572)
		(drill 0.2032)
		(layers "F.Cu" "B.Cu")
		(net "GND")
	)
	(via
		(at 300.903894 -354.870004)
		(size 0.508)
		(drill 0.254)
		(layers "F.Cu" "B.Cu")
		(net "GND")
	)
	(via
		(at 445.577214 -197.316598)
		(size 0.4572)
		(drill 0.2032)
		(layers "F.Cu" "B.Cu")
		(net "GND")
	)
	(via
		(at 397.077438 -410.664152)
		(size 0.4572)
		(drill 0.254)
		(layers "F.Cu" "B.Cu")
		(net "GND")
	)
	(via
		(at 352.2218 -334.282034)
		(size 0.49022)
		(drill 0.254)
		(layers "F.Cu" "B.Cu")
		(net "GND")
	)
	(via
		(at 299.004482 -232.166668)
		(size 0.4572)
		(drill 0.2032)
		(layers "F.Cu" "B.Cu")
		(net "GND")
	)
	(via
		(at 294.904414 -272.116804)
		(size 0.4572)
		(drill 0.2032)
		(layers "F.Cu" "B.Cu")
		(net "GND")
	)
	(via
		(at 135.787638 -341.766906)
		(size 0.49022)
		(drill 0.254)
		(layers "F.Cu" "B.Cu")
		(net "GND")
	)
	(via
		(at 351.231962 -281.59202)
		(size 0.4572)
		(drill 0.2032)
		(layers "F.Cu" "B.Cu")
		(net "GND")
	)
	(via
		(at 455.011282 -232.166668)
		(size 0.4572)
		(drill 0.2032)
		(layers "F.Cu" "B.Cu")
		(net "GND")
	)
	(via
		(at 111.640366 -222.761556)
		(size 0.4572)
		(drill 0.2032)
		(layers "F.Cu" "B.Cu")
		(net "GND")
	)
	(via
		(at 128.666748 -281.59202)
		(size 0.4572)
		(drill 0.2032)
		(layers "F.Cu" "B.Cu")
		(net "GND")
	)
	(via
		(at 110.340648 -257.989324)
		(size 0.4572)
		(drill 0.2032)
		(layers "F.Cu" "B.Cu")
		(net "GND")
	)
	(via
		(at 167.461946 -251.716794)
		(size 0.4572)
		(drill 0.2032)
		(layers "F.Cu" "B.Cu")
		(net "GND")
	)
	(via
		(at 389.843772 -18.235422)
		(size 0.508)
		(drill 0.254)
		(layers "F.Cu" "B.Cu")
		(net "GND")
	)
	(via
		(at 323.42074 -401.492212)
		(size 0.4572)
		(drill 0.254)
		(layers "F.Cu" "B.Cu")
		(net "GND")
	)
	(via
		(at 279.816814 -267.016738)
		(size 0.4572)
		(drill 0.2032)
		(layers "F.Cu" "B.Cu")
		(net "GND")
	)
	(via
		(at 450.911214 -298.466764)
		(size 0.4572)
		(drill 0.2032)
		(layers "F.Cu" "B.Cu")
		(net "GND")
	)
	(via
		(at 97.073466 -244.73662)
		(size 0.4572)
		(drill 0.2032)
		(layers "F.Cu" "B.Cu")
		(net "GND")
	)
	(via
		(at 194.833494 -25.389586)
		(size 0.508)
		(drill 0.254)
		(layers "F.Cu" "B.Cu")
		(net "GND")
	)
	(via
		(at 194.193414 -271.266666)
		(size 0.4572)
		(drill 0.2032)
		(layers "F.Cu" "B.Cu")
		(net "GND")
	)
	(via
		(at 272.273014 -260.21665)
		(size 0.4572)
		(drill 0.2032)
		(layers "F.Cu" "B.Cu")
		(net "GND")
	)
	(via
		(at 296.794682 -247.466612)
		(size 0.4572)
		(drill 0.2032)
		(layers "F.Cu" "B.Cu")
		(net "GND")
	)
	(via
		(at 300.238414 -298.466764)
		(size 0.4572)
		(drill 0.2032)
		(layers "F.Cu" "B.Cu")
		(net "GND")
	)
	(via
		(at 372.26748 -244.73662)
		(size 0.4572)
		(drill 0.2032)
		(layers "F.Cu" "B.Cu")
		(net "GND")
	)
	(via
		(at 287.360614 -263.616694)
		(size 0.4572)
		(drill 0.2032)
		(layers "F.Cu" "B.Cu")
		(net "GND")
	)
	(via
		(at 311.882282 -232.166668)
		(size 0.4572)
		(drill 0.2032)
		(layers "F.Cu" "B.Cu")
		(net "GND")
	)
	(via
		(at 430.200054 -130.964178)
		(size 0.508)
		(drill 0.254)
		(layers "F.Cu" "B.Cu")
		(net "GND")
	)
	(via
		(at 62.051946 -295.06672)
		(size 0.4572)
		(drill 0.2032)
		(layers "F.Cu" "B.Cu")
		(net "GND")
	)
	(via
		(at 264.729214 -250.016772)
		(size 0.4572)
		(drill 0.2032)
		(layers "F.Cu" "B.Cu")
		(net "GND")
	)
	(via
		(at 388.16153 -403.883876)
		(size 0.4064)
		(drill 0.2032)
		(layers "F.Cu" "B.Cu")
		(net "GND")
	)
	(via
		(at 368.148616 -271.825212)
		(size 0.4572)
		(drill 0.2032)
		(layers "F.Cu" "B.Cu")
		(net "GND")
	)
	(via
		(at 296.461688 -360.83621)
		(size 0.49022)
		(drill 0.254)
		(layers "F.Cu" "B.Cu")
		(net "GND")
	)
	(via
		(at 264.729214 -216.016586)
		(size 0.4572)
		(drill 0.2032)
		(layers "F.Cu" "B.Cu")
		(net "GND")
	)
	(via
		(at 41.310814 -244.066568)
		(size 0.4572)
		(drill 0.2032)
		(layers "F.Cu" "B.Cu")
		(net "GND")
	)
	(via
		(at 105.312718 -338.702142)
		(size 0.508)
		(drill 0.254)
		(layers "F.Cu" "B.Cu")
		(net "GND")
	)
	(via
		(at 188.90488 -102.707948)
		(size 0.508)
		(drill 0.254)
		(layers "F.Cu" "B.Cu")
		(net "GND")
	)
	(via
		(at 22.123146 -203.266802)
		(size 0.4572)
		(drill 0.2032)
		(layers "F.Cu" "B.Cu")
		(net "GND")
	)
	(via
		(at 130.493262 -409.396184)
		(size 0.4572)
		(drill 0.254)
		(layers "F.Cu" "B.Cu")
		(net "GND")
	)
	(via
		(at 26.223214 -230.466646)
		(size 0.4572)
		(drill 0.2032)
		(layers "F.Cu" "B.Cu")
		(net "GND")
	)
	(via
		(at 289.250882 -241.516662)
		(size 0.4572)
		(drill 0.2032)
		(layers "F.Cu" "B.Cu")
		(net "GND")
	)
	(via
		(at 130.350006 -426.69968)
		(size 0.4572)
		(drill 0.2032)
		(layers "F.Cu" "B.Cu")
		(net "GND")
	)
	(via
		(at 304.338482 -232.166668)
		(size 0.4572)
		(drill 0.2032)
		(layers "F.Cu" "B.Cu")
		(net "GND")
	)
	(via
		(at 304.338482 -202.416664)
		(size 0.4572)
		(drill 0.2032)
		(layers "F.Cu" "B.Cu")
		(net "GND")
	)
	(via
		(at 264.729214 -278.066754)
		(size 0.4572)
		(drill 0.2032)
		(layers "F.Cu" "B.Cu")
		(net "GND")
	)
	(via
		(at 373.67718 -240.667286)
		(size 0.4572)
		(drill 0.2032)
		(layers "F.Cu" "B.Cu")
		(net "GND")
	)
	(via
		(at 420.736014 -301.866808)
		(size 0.4572)
		(drill 0.2032)
		(layers "F.Cu" "B.Cu")
		(net "GND")
	)
	(via
		(at 392.34999 -428.851314)
		(size 0.4572)
		(drill 0.2032)
		(layers "F.Cu" "B.Cu")
		(net "GND")
	)
	(via
		(at 259.075682 -198.166736)
		(size 0.4572)
		(drill 0.2032)
		(layers "F.Cu" "B.Cu")
		(net "GND")
	)
	(via
		(at 369.000278 -424.535346)
		(size 0.508)
		(drill 0.254)
		(layers "F.Cu" "B.Cu")
		(net "GND")
	)
	(via
		(at 307.566314 -208.366614)
		(size 0.4572)
		(drill 0.2032)
		(layers "F.Cu" "B.Cu")
		(net "GND")
	)
	(via
		(at 261.285482 -219.41663)
		(size 0.4572)
		(drill 0.2032)
		(layers "F.Cu" "B.Cu")
		(net "GND")
	)
	(via
		(at 120.97639 -243.846604)
		(size 0.4572)
		(drill 0.2032)
		(layers "F.Cu" "B.Cu")
		(net "GND")
	)
	(via
		(at 135.245094 -283.219906)
		(size 0.4572)
		(drill 0.2032)
		(layers "F.Cu" "B.Cu")
		(net "GND")
	)
	(via
		(at 43.582082 -18.246344)
		(size 0.508)
		(drill 0.254)
		(layers "F.Cu" "B.Cu")
		(net "GND")
	)
	(via
		(at 104.121966 -221.133924)
		(size 0.4572)
		(drill 0.2032)
		(layers "F.Cu" "B.Cu")
		(net "GND")
	)
	(via
		(at 458.455014 -263.616694)
		(size 0.4572)
		(drill 0.2032)
		(layers "F.Cu" "B.Cu")
		(net "GND")
	)
	(via
		(at 63.726314 -210.066636)
		(size 0.4572)
		(drill 0.2032)
		(layers "F.Cu" "B.Cu")
		(net "GND")
	)
	(via
		(at 343.507568 -410.030168)
		(size 0.4064)
		(drill 0.2032)
		(layers "F.Cu" "B.Cu")
		(net "GND")
	)
	(via
		(at 285.150814 -214.316564)
		(size 0.4572)
		(drill 0.2032)
		(layers "F.Cu" "B.Cu")
		(net "GND")
	)
	(via
		(at 184.439814 -247.466612)
		(size 0.4572)
		(drill 0.2032)
		(layers "F.Cu" "B.Cu")
		(net "GND")
	)
	(via
		(at 268.829282 -264.466578)
		(size 0.4572)
		(drill 0.2032)
		(layers "F.Cu" "B.Cu")
		(net "GND")
	)
	(via
		(at 419.502082 -215.166702)
		(size 0.4572)
		(drill 0.2032)
		(layers "F.Cu" "B.Cu")
		(net "GND")
	)
	(via
		(at 317.381636 -410.664152)
		(size 0.4572)
		(drill 0.254)
		(layers "F.Cu" "B.Cu")
		(net "GND")
	)
	(via
		(at 438.033414 -248.31675)
		(size 0.4572)
		(drill 0.2032)
		(layers "F.Cu" "B.Cu")
		(net "GND")
	)
	(via
		(at 182.549546 -272.116804)
		(size 0.4572)
		(drill 0.2032)
		(layers "F.Cu" "B.Cu")
		(net "GND")
	)
	(via
		(at 9.245346 -285.716726)
		(size 0.4572)
		(drill 0.2032)
		(layers "F.Cu" "B.Cu")
		(net "GND")
	)
	(via
		(at 106.431842 -96.96704)
		(size 0.508)
		(drill 0.254)
		(layers "F.Cu" "B.Cu")
		(net "GND")
	)
	(via
		(at 120.678194 -287.28924)
		(size 0.4572)
		(drill 0.2032)
		(layers "F.Cu" "B.Cu")
		(net "GND")
	)
	(via
		(at 276.373082 -241.516662)
		(size 0.4572)
		(drill 0.2032)
		(layers "F.Cu" "B.Cu")
		(net "GND")
	)
	(via
		(at 128.763522 -339.114638)
		(size 0.49022)
		(drill 0.254)
		(layers "F.Cu" "B.Cu")
		(net "GND")
	)
	(via
		(at 415.402014 -300.166786)
		(size 0.4572)
		(drill 0.2032)
		(layers "F.Cu" "B.Cu")
		(net "GND")
	)
	(via
		(at 300.238414 -306.116736)
		(size 0.4572)
		(drill 0.2032)
		(layers "F.Cu" "B.Cu")
		(net "GND")
	)
	(via
		(at 56.83885 -164.422074)
		(size 0.49022)
		(drill 0.254)
		(layers "F.Cu" "B.Cu")
		(net "GND")
	)
	(via
		(at 385.534916 -287.41624)
		(size 0.4572)
		(drill 0.2032)
		(layers "F.Cu" "B.Cu")
		(net "GND")
	)
	(via
		(at 212.724746 -261.916672)
		(size 0.4572)
		(drill 0.2032)
		(layers "F.Cu" "B.Cu")
		(net "GND")
	)
	(via
		(at 203.1492 -93.6498)
		(size 0.508)
		(drill 0.254)
		(layers "F.Cu" "B.Cu")
		(net "GND")
	)
	(via
		(at 70.571106 -409.396184)
		(size 0.4572)
		(drill 0.254)
		(layers "F.Cu" "B.Cu")
		(net "GND")
	)
	(via
		(at 44.754546 -272.116804)
		(size 0.4572)
		(drill 0.2032)
		(layers "F.Cu" "B.Cu")
		(net "GND")
	)
	(via
		(at 302.448214 -248.31675)
		(size 0.4572)
		(drill 0.2032)
		(layers "F.Cu" "B.Cu")
		(net "GND")
	)
	(via
		(at 157.349952 -427.699678)
		(size 0.4572)
		(drill 0.2032)
		(layers "F.Cu" "B.Cu")
		(net "GND")
	)
	(via
		(at 422.945814 -317.166752)
		(size 0.4572)
		(drill 0.2032)
		(layers "F.Cu" "B.Cu")
		(net "GND")
	)
	(via
		(at 309.992014 -268.71676)
		(size 0.4572)
		(drill 0.2032)
		(layers "F.Cu" "B.Cu")
		(net "GND")
	)
	(via
		(at 58.608214 -267.866622)
		(size 0.4572)
		(drill 0.2032)
		(layers "F.Cu" "B.Cu")
		(net "GND")
	)
	(via
		(at 350.1517 -28.115768)
		(size 0.508)
		(drill 0.254)
		(layers "F.Cu" "B.Cu")
		(net "GND")
	)
	(via
		(at 285.150814 -212.616796)
		(size 0.4572)
		(drill 0.2032)
		(layers "F.Cu" "B.Cu")
		(net "GND")
	)
	(via
		(at 353.581462 -267.755878)
		(size 0.4572)
		(drill 0.2032)
		(layers "F.Cu" "B.Cu")
		(net "GND")
	)
	(via
		(at 259.075682 -216.866724)
		(size 0.4572)
		(drill 0.2032)
		(layers "F.Cu" "B.Cu")
		(net "GND")
	)
	(via
		(at 402.84273 -407.00452)
		(size 0.4064)
		(drill 0.2032)
		(layers "F.Cu" "B.Cu")
		(net "GND")
	)
	(via
		(at 113.52022 -245.550944)
		(size 0.4572)
		(drill 0.2032)
		(layers "F.Cu" "B.Cu")
		(net "GND")
	)
	(via
		(at 414.070292 -172.834554)
		(size 0.49022)
		(drill 0.254)
		(layers "F.Cu" "B.Cu")
		(net "GND")
	)
	(via
		(at 417.292282 -267.866622)
		(size 0.4572)
		(drill 0.2032)
		(layers "F.Cu" "B.Cu")
		(net "GND")
	)
	(via
		(at 361.569762 -283.219906)
		(size 0.4572)
		(drill 0.2032)
		(layers "F.Cu" "B.Cu")
		(net "GND")
	)
	(via
		(at 375.557034 -230.900478)
		(size 0.4572)
		(drill 0.2032)
		(layers "F.Cu" "B.Cu")
		(net "GND")
	)
	(via
		(at 127.804926 -120.820434)
		(size 0.508)
		(drill 0.254)
		(layers "F.Cu" "B.Cu")
		(net "GND")
	)
	(via
		(at 355.28758 -44.998386)
		(size 0.508)
		(drill 0.254)
		(layers "F.Cu" "B.Cu")
		(net "GND")
	)
	(via
		(at 449.677282 -308.666642)
		(size 0.4572)
		(drill 0.2032)
		(layers "F.Cu" "B.Cu")
		(net "GND")
	)
	(via
		(at 397.43126 -168.478708)
		(size 0.508)
		(drill 0.254)
		(layers "F.Cu" "B.Cu")
		(net "GND")
	)
	(via
		(at 289.250882 -266.1666)
		(size 0.4572)
		(drill 0.2032)
		(layers "F.Cu" "B.Cu")
		(net "GND")
	)
	(via
		(at 389.604758 -401.492212)
		(size 0.4572)
		(drill 0.254)
		(layers "F.Cu" "B.Cu")
		(net "GND")
	)
	(via
		(at 212.724746 -208.366614)
		(size 0.4572)
		(drill 0.2032)
		(layers "F.Cu" "B.Cu")
		(net "GND")
	)
	(via
		(at 384.015234 -226.017328)
		(size 0.4572)
		(drill 0.2032)
		(layers "F.Cu" "B.Cu")
		(net "GND")
	)
	(via
		(at 121.490232 -365.756444)
		(size 0.508)
		(drill 0.254)
		(layers "F.Cu" "B.Cu")
		(net "GND")
	)
	(via
		(at 132.425694 -283.219906)
		(size 0.4572)
		(drill 0.2032)
		(layers "F.Cu" "B.Cu")
		(net "GND")
	)
	(via
		(at 413.192214 -306.116736)
		(size 0.4572)
		(drill 0.2032)
		(layers "F.Cu" "B.Cu")
		(net "GND")
	)
	(via
		(at 435.823614 -311.216802)
		(size 0.4572)
		(drill 0.2032)
		(layers "F.Cu" "B.Cu")
		(net "GND")
	)
	(via
		(at 350.846898 -240.928906)
		(size 0.4572)
		(drill 0.2032)
		(layers "F.Cu" "B.Cu")
		(net "GND")
	)
	(via
		(at 378.016262 -284.033722)
		(size 0.4572)
		(drill 0.2032)
		(layers "F.Cu" "B.Cu")
		(net "GND")
	)
	(via
		(at 332.61046 -403.249892)
		(size 0.4572)
		(drill 0.254)
		(layers "F.Cu" "B.Cu")
		(net "GND")
	)
	(via
		(at 261.285482 -272.966688)
		(size 0.4572)
		(drill 0.2032)
		(layers "F.Cu" "B.Cu")
		(net "GND")
	)
	(via
		(at 32.06115 -128.109472)
		(size 0.508)
		(drill 0.254)
		(layers "F.Cu" "B.Cu")
		(net "GND")
	)
	(via
		(at 22.123146 -311.216802)
		(size 0.4572)
		(drill 0.2032)
		(layers "F.Cu" "B.Cu")
		(net "GND")
	)
	(via
		(at 279.816814 -258.516628)
		(size 0.4572)
		(drill 0.2032)
		(layers "F.Cu" "B.Cu")
		(net "GND")
	)
	(via
		(at 337.604862 -274.266914)
		(size 0.4572)
		(drill 0.2032)
		(layers "F.Cu" "B.Cu")
		(net "GND")
	)
	(via
		(at 442.133482 -204.116686)
		(size 0.4572)
		(drill 0.2032)
		(layers "F.Cu" "B.Cu")
		(net "GND")
	)
	(via
		(at 79.186532 -31.615126)
		(size 0.508)
		(drill 0.254)
		(layers "F.Cu" "B.Cu")
		(net "GND")
	)
	(via
		(at 95.077026 -407.638504)
		(size 0.4572)
		(drill 0.254)
		(layers "F.Cu" "B.Cu")
		(net "GND")
	)
	(via
		(at 195.427346 -300.166786)
		(size 0.4572)
		(drill 0.2032)
		(layers "F.Cu" "B.Cu")
		(net "GND")
	)
	(via
		(at 349.822262 -275.8948)
		(size 0.4572)
		(drill 0.2032)
		(layers "F.Cu" "B.Cu")
		(net "GND")
	)
	(via
		(at 462.555082 -284.866588)
		(size 0.4572)
		(drill 0.2032)
		(layers "F.Cu" "B.Cu")
		(net "GND")
	)
	(via
		(at 187.883546 -292.516814)
		(size 0.4572)
		(drill 0.2032)
		(layers "F.Cu" "B.Cu")
		(net "GND")
	)
	(via
		(at 106.001566 -219.506038)
		(size 0.4572)
		(drill 0.2032)
		(layers "F.Cu" "B.Cu")
		(net "GND")
	)
	(via
		(at 420.736014 -260.21665)
		(size 0.4572)
		(drill 0.2032)
		(layers "F.Cu" "B.Cu")
		(net "GND")
	)
	(via
		(at 339.374734 -226.831144)
		(size 0.4572)
		(drill 0.2032)
		(layers "F.Cu" "B.Cu")
		(net "GND")
	)
	(via
		(at 33.767014 -286.56661)
		(size 0.4572)
		(drill 0.2032)
		(layers "F.Cu" "B.Cu")
		(net "GND")
	)
	(via
		(at 172.795946 -265.316716)
		(size 0.4572)
		(drill 0.2032)
		(layers "F.Cu" "B.Cu")
		(net "GND")
	)
	(via
		(at 168.43883 -425.922948)
		(size 0.508)
		(drill 0.254)
		(layers "F.Cu" "B.Cu")
		(net "GND")
	)
	(via
		(at 112.677702 -333.355188)
		(size 0.49022)
		(drill 0.254)
		(layers "F.Cu" "B.Cu")
		(net "GND")
	)
	(via
		(at 340.894416 -275.08073)
		(size 0.4572)
		(drill 0.2032)
		(layers "F.Cu" "B.Cu")
		(net "GND")
	)
	(via
		(at 467.535514 -124.32538)
		(size 0.508)
		(drill 0.254)
		(layers "F.Cu" "B.Cu")
		(net "GND")
	)
	(via
		(at 153.555954 -410.030168)
		(size 0.4064)
		(drill 0.2032)
		(layers "F.Cu" "B.Cu")
		(net "GND")
	)
	(via
		(at 50.428906 -16.978376)
		(size 0.508)
		(drill 0.254)
		(layers "F.Cu" "B.Cu")
		(net "GND")
	)
	(via
		(at 359.110534 -230.086662)
		(size 0.4572)
		(drill 0.2032)
		(layers "F.Cu" "B.Cu")
		(net "GND")
	)
	(via
		(at 370.968016 -276.708616)
		(size 0.4572)
		(drill 0.2032)
		(layers "F.Cu" "B.Cu")
		(net "GND")
	)
	(via
		(at 306.748688 -410.030168)
		(size 0.4064)
		(drill 0.2032)
		(layers "F.Cu" "B.Cu")
		(net "GND")
	)
	(via
		(at 377.54814 -335.976214)
		(size 0.49022)
		(drill 0.254)
		(layers "F.Cu" "B.Cu")
		(net "GND")
	)
	(via
		(at 374.61698 -247.178322)
		(size 0.4572)
		(drill 0.2032)
		(layers "F.Cu" "B.Cu")
		(net "GND")
	)
	(via
		(at 39.420546 -306.116736)
		(size 0.4572)
		(drill 0.2032)
		(layers "F.Cu" "B.Cu")
		(net "GND")
	)
	(via
		(at 117.279166 -219.506038)
		(size 0.4572)
		(drill 0.2032)
		(layers "F.Cu" "B.Cu")
		(net "GND")
	)
	(via
		(at 140.706602 -338.510372)
		(size 0.508)
		(drill 0.254)
		(layers "F.Cu" "B.Cu")
		(net "GND")
	)
	(via
		(at 52.298346 -267.016738)
		(size 0.4572)
		(drill 0.2032)
		(layers "F.Cu" "B.Cu")
		(net "GND")
	)
	(via
		(at 257.976878 -101.857302)
		(size 0.508)
		(drill 0.254)
		(layers "F.Cu" "B.Cu")
		(net "GND")
	)
	(via
		(at 243.52377 -166.897812)
		(size 0.508)
		(drill 0.254)
		(layers "F.Cu" "B.Cu")
		(net "GND")
	)
	(via
		(at 34.620454 -45.49013)
		(size 0.508)
		(drill 0.254)
		(layers "F.Cu" "B.Cu")
		(net "GND")
	)
	(via
		(at 205.180946 -273.816572)
		(size 0.4572)
		(drill 0.2032)
		(layers "F.Cu" "B.Cu")
		(net "GND")
	)
	(via
		(at 196.930518 -194.06235)
		(size 0.508)
		(drill 0.254)
		(layers "F.Cu" "B.Cu")
		(net "GND")
	)
	(via
		(at 253.97841 -45.859192)
		(size 0.508)
		(drill 0.254)
		(layers "F.Cu" "B.Cu")
		(net "GND")
	)
	(via
		(at 18.679414 -269.566644)
		(size 0.4572)
		(drill 0.2032)
		(layers "F.Cu" "B.Cu")
		(net "GND")
	)
	(via
		(at 370.51488 -44.160948)
		(size 0.508)
		(drill 0.254)
		(layers "F.Cu" "B.Cu")
		(net "GND")
	)
	(via
		(at 67.507866 -406.34666)
		(size 0.4572)
		(drill 0.254)
		(layers "F.Cu" "B.Cu")
		(net "GND")
	)
	(via
		(at 422.945814 -234.716574)
		(size 0.4572)
		(drill 0.2032)
		(layers "F.Cu" "B.Cu")
		(net "GND")
	)
	(via
		(at 408.96921 -407.00452)
		(size 0.4064)
		(drill 0.2032)
		(layers "F.Cu" "B.Cu")
		(net "GND")
	)
	(via
		(at 444.38951 -69.570854)
		(size 0.508)
		(drill 0.254)
		(layers "F.Cu" "B.Cu")
		(net "GND")
	)
	(via
		(at 110.483396 -360.753406)
		(size 0.508)
		(drill 0.254)
		(layers "F.Cu" "B.Cu")
		(net "GND")
	)
	(via
		(at 2.764536 -86.790022)
		(size 0.508)
		(drill 0.254)
		(layers "F.Cu" "B.Cu")
		(net "GND")
	)
	(via
		(at 81.380838 -410.030168)
		(size 0.4064)
		(drill 0.2032)
		(layers "F.Cu" "B.Cu")
		(net "GND")
	)
	(via
		(at 99.422966 -229.272846)
		(size 0.4572)
		(drill 0.2032)
		(layers "F.Cu" "B.Cu")
		(net "GND")
	)
	(via
		(at 279.816814 -313.766708)
		(size 0.4572)
		(drill 0.2032)
		(layers "F.Cu" "B.Cu")
		(net "GND")
	)
	(via
		(at 439.923682 -277.216616)
		(size 0.4572)
		(drill 0.2032)
		(layers "F.Cu" "B.Cu")
		(net "GND")
	)
	(via
		(at 88.255094 -279.964134)
		(size 0.4572)
		(drill 0.2032)
		(layers "F.Cu" "B.Cu")
		(net "GND")
	)
	(via
		(at 281.707082 -221.116652)
		(size 0.4572)
		(drill 0.2032)
		(layers "F.Cu" "B.Cu")
		(net "GND")
	)
	(via
		(at 453.666606 -69.461634)
		(size 0.508)
		(drill 0.254)
		(layers "F.Cu" "B.Cu")
		(net "GND")
	)
	(via
		(at 355.91496 -43.604688)
		(size 0.508)
		(drill 0.254)
		(layers "F.Cu" "B.Cu")
		(net "GND")
	)
	(via
		(at 9.245346 -234.716574)
		(size 0.4572)
		(drill 0.2032)
		(layers "F.Cu" "B.Cu")
		(net "GND")
	)
	(via
		(at 447.687446 -72.822816)
		(size 0.508)
		(drill 0.254)
		(layers "F.Cu" "B.Cu")
		(net "GND")
	)
	(via
		(at 259.075682 -278.916638)
		(size 0.4572)
		(drill 0.2032)
		(layers "F.Cu" "B.Cu")
		(net "GND")
	)
	(via
		(at 467.535514 -368.16538)
		(size 0.508)
		(drill 0.254)
		(layers "F.Cu" "B.Cu")
		(net "GND")
	)
	(via
		(at 264.752074 -319.401952)
		(size 0.4572)
		(drill 0.2032)
		(layers "F.Cu" "B.Cu")
		(net "GND")
	)
	(via
		(at 257.185414 -208.366614)
		(size 0.4572)
		(drill 0.2032)
		(layers "F.Cu" "B.Cu")
		(net "GND")
	)
	(via
		(at 389.268208 -340.284816)
		(size 0.508)
		(drill 0.254)
		(layers "F.Cu" "B.Cu")
		(net "GND")
	)
	(via
		(at 303.022 -51.939444)
		(size 0.508)
		(drill 0.254)
		(layers "F.Cu" "B.Cu")
		(net "GND")
	)
	(via
		(at 337.604862 -264.50036)
		(size 0.4572)
		(drill 0.2032)
		(layers "F.Cu" "B.Cu")
		(net "GND")
	)
	(via
		(at 447.467482 -219.41663)
		(size 0.4572)
		(drill 0.2032)
		(layers "F.Cu" "B.Cu")
		(net "GND")
	)
	(via
		(at 344.183462 -254.733552)
		(size 0.4572)
		(drill 0.2032)
		(layers "F.Cu" "B.Cu")
		(net "GND")
	)
	(via
		(at 383.545334 -231.714548)
		(size 0.4572)
		(drill 0.2032)
		(layers "F.Cu" "B.Cu")
		(net "GND")
	)
	(via
		(at 36.765992 -384.779012)
		(size 0.508)
		(drill 0.254)
		(layers "F.Cu" "B.Cu")
		(net "GND")
	)
	(via
		(at 209.281014 -266.1666)
		(size 0.4572)
		(drill 0.2032)
		(layers "F.Cu" "B.Cu")
		(net "GND")
	)
	(via
		(at 281.707082 -314.616592)
		(size 0.4572)
		(drill 0.2032)
		(layers "F.Cu" "B.Cu")
		(net "GND")
	)
	(via
		(at 434.467 -136.693148)
		(size 0.508)
		(drill 0.254)
		(layers "F.Cu" "B.Cu")
		(net "GND")
	)
	(via
		(at 396.690596 -18.235422)
		(size 0.508)
		(drill 0.254)
		(layers "F.Cu" "B.Cu")
		(net "GND")
	)
	(via
		(at 118.218966 -219.506038)
		(size 0.4572)
		(drill 0.2032)
		(layers "F.Cu" "B.Cu")
		(net "GND")
	)
	(via
		(at 460.664814 -267.016738)
		(size 0.4572)
		(drill 0.2032)
		(layers "F.Cu" "B.Cu")
		(net "GND")
	)
	(via
		(at 172.795946 -238.966756)
		(size 0.4572)
		(drill 0.2032)
		(layers "F.Cu" "B.Cu")
		(net "GND")
	)
	(via
		(at 79.67345 -401.492212)
		(size 0.4572)
		(drill 0.254)
		(layers "F.Cu" "B.Cu")
		(net "GND")
	)
	(via
		(at 358.170734 -243.108988)
		(size 0.4572)
		(drill 0.2032)
		(layers "F.Cu" "B.Cu")
		(net "GND")
	)
	(via
		(at 464.764882 -216.866724)
		(size 0.4572)
		(drill 0.2032)
		(layers "F.Cu" "B.Cu")
		(net "GND")
	)
	(via
		(at 401.76069 -407.00452)
		(size 0.4064)
		(drill 0.2032)
		(layers "F.Cu" "B.Cu")
		(net "GND")
	)
	(via
		(at 274.163282 -245.76659)
		(size 0.4572)
		(drill 0.2032)
		(layers "F.Cu" "B.Cu")
		(net "GND")
	)
	(via
		(at 396.349982 -438.499758)
		(size 0.4572)
		(drill 0.2032)
		(layers "F.Cu" "B.Cu")
		(net "GND")
	)
	(via
		(at 58.608214 -280.61666)
		(size 0.4572)
		(drill 0.2032)
		(layers "F.Cu" "B.Cu")
		(net "GND")
	)
	(via
		(at 207.071214 -284.866588)
		(size 0.4572)
		(drill 0.2032)
		(layers "F.Cu" "B.Cu")
		(net "GND")
	)
	(via
		(at 422.945814 -306.116736)
		(size 0.4572)
		(drill 0.2032)
		(layers "F.Cu" "B.Cu")
		(net "GND")
	)
	(via
		(at 76.250038 -435.0512)
		(size 0.4572)
		(drill 0.2032)
		(layers "F.Cu" "B.Cu")
		(net "GND")
	)
	(via
		(at 134.195566 -232.528364)
		(size 0.4572)
		(drill 0.2032)
		(layers "F.Cu" "B.Cu")
		(net "GND")
	)
	(via
		(at 384.387852 -341.766906)
		(size 0.49022)
		(drill 0.254)
		(layers "F.Cu" "B.Cu")
		(net "GND")
	)
	(via
		(at 160.112202 -285.667196)
		(size 0.4572)
		(drill 0.2032)
		(layers "F.Cu" "B.Cu")
		(net "GND")
	)
	(via
		(at 33.037018 -165.154102)
		(size 0.508)
		(drill 0.254)
		(layers "F.Cu" "B.Cu")
		(net "GND")
	)
	(via
		(at 392.667998 -403.249892)
		(size 0.4572)
		(drill 0.254)
		(layers "F.Cu" "B.Cu")
		(net "GND")
	)
	(via
		(at 449.194682 -42.23004)
		(size 0.508)
		(drill 0.254)
		(layers "F.Cu" "B.Cu")
		(net "GND")
	)
	(via
		(at 357.609902 -292.955726)
		(size 0.508)
		(drill 0.254)
		(layers "F.Cu" "B.Cu")
		(net "GND")
	)
	(via
		(at 328.765916 -26.901648)
		(size 0.508)
		(drill 0.254)
		(layers "F.Cu" "B.Cu")
		(net "GND")
	)
	(via
		(at 306.548282 -226.216718)
		(size 0.4572)
		(drill 0.2032)
		(layers "F.Cu" "B.Cu")
		(net "GND")
	)
	(via
		(at 259.831078 -63.380112)
		(size 0.6604)
		(drill 0.3302)
		(layers "F.Cu" "B.Cu")
		(net "GND")
	)
	(via
		(at 427.045882 -221.116652)
		(size 0.4572)
		(drill 0.2032)
		(layers "F.Cu" "B.Cu")
		(net "GND")
	)
	(via
		(at 231.553004 -132.95122)
		(size 0.508)
		(drill 0.254)
		(layers "F.Cu" "B.Cu")
		(net "GND")
	)
	(via
		(at 312.51398 -410.664152)
		(size 0.4572)
		(drill 0.254)
		(layers "F.Cu" "B.Cu")
		(net "GND")
	)
	(via
		(at 424.836082 -275.516594)
		(size 0.4572)
		(drill 0.2032)
		(layers "F.Cu" "B.Cu")
		(net "GND")
	)
	(via
		(at 262.519414 -214.316564)
		(size 0.4572)
		(drill 0.2032)
		(layers "F.Cu" "B.Cu")
		(net "GND")
	)
	(via
		(at 338.904834 -234.15625)
		(size 0.4572)
		(drill 0.2032)
		(layers "F.Cu" "B.Cu")
		(net "GND")
	)
	(via
		(at 164.462714 -403.883876)
		(size 0.4064)
		(drill 0.2032)
		(layers "F.Cu" "B.Cu")
		(net "GND")
	)
	(via
		(at 270.063214 -206.666592)
		(size 0.4572)
		(drill 0.2032)
		(layers "F.Cu" "B.Cu")
		(net "GND")
	)
	(via
		(at 97.183448 -262.872474)
		(size 0.4572)
		(drill 0.2032)
		(layers "F.Cu" "B.Cu")
		(net "GND")
	)
	(via
		(at 321.250056 -430.147222)
		(size 0.4572)
		(drill 0.2032)
		(layers "F.Cu" "B.Cu")
		(net "GND")
	)
	(via
		(at 240.58626 -133.94182)
		(size 0.508)
		(drill 0.254)
		(layers "F.Cu" "B.Cu")
		(net "GND")
	)
	(via
		(at 336.665062 -279.150318)
		(size 0.4572)
		(drill 0.2032)
		(layers "F.Cu" "B.Cu")
		(net "GND")
	)
	(via
		(at 453.121014 -208.366614)
		(size 0.4572)
		(drill 0.2032)
		(layers "F.Cu" "B.Cu")
		(net "GND")
	)
	(via
		(at 165.252146 -214.316564)
		(size 0.4572)
		(drill 0.2032)
		(layers "F.Cu" "B.Cu")
		(net "GND")
	)
	(via
		(at 216.824814 -258.516628)
		(size 0.4572)
		(drill 0.2032)
		(layers "F.Cu" "B.Cu")
		(net "GND")
	)
	(via
		(at 55.871618 -170.689524)
		(size 0.508)
		(drill 0.254)
		(layers "F.Cu" "B.Cu")
		(net "GND")
	)
	(via
		(at 13.345414 -261.066788)
		(size 0.4572)
		(drill 0.2032)
		(layers "F.Cu" "B.Cu")
		(net "GND")
	)
	(via
		(at 85.79993 -404.51786)
		(size 0.4572)
		(drill 0.254)
		(layers "F.Cu" "B.Cu")
		(net "GND")
	)
	(via
		(at 446.548002 -17.433798)
		(size 0.508)
		(drill 0.254)
		(layers "F.Cu" "B.Cu")
		(net "GND")
	)
	(via
		(at 315.250068 -433.899564)
		(size 0.4572)
		(drill 0.2032)
		(layers "F.Cu" "B.Cu")
		(net "GND")
	)
	(via
		(at 377.90628 -249.620024)
		(size 0.4572)
		(drill 0.2032)
		(layers "F.Cu" "B.Cu")
		(net "GND")
	)
	(via
		(at 167.461946 -216.016586)
		(size 0.4572)
		(drill 0.2032)
		(layers "F.Cu" "B.Cu")
		(net "GND")
	)
	(via
		(at 103.14559 -331.776832)
		(size 0.49022)
		(drill 0.254)
		(layers "F.Cu" "B.Cu")
		(net "GND")
	)
	(via
		(at 141.400022 -404.51786)
		(size 0.4572)
		(drill 0.254)
		(layers "F.Cu" "B.Cu")
		(net "GND")
	)
	(via
		(at 265.081766 -94.634812)
		(size 0.508)
		(drill 0.254)
		(layers "F.Cu" "B.Cu")
		(net "GND")
	)
	(via
		(at 108.368846 -331.71892)
		(size 0.508)
		(drill 0.254)
		(layers "F.Cu" "B.Cu")
		(net "GND")
	)
	(via
		(at 35.976814 -224.516696)
		(size 0.4572)
		(drill 0.2032)
		(layers "F.Cu" "B.Cu")
		(net "GND")
	)
	(via
		(at 96.791272 -425.405296)
		(size 0.508)
		(drill 0.254)
		(layers "F.Cu" "B.Cu")
		(net "GND")
	)
	(via
		(at 408.151584 -216.016586)
		(size 0.4572)
		(drill 0.2032)
		(layers "F.Cu" "B.Cu")
		(net "GND")
	)
	(via
		(at 412.18358 -158.435548)
		(size 0.508)
		(drill 0.254)
		(layers "F.Cu" "B.Cu")
		(net "GND")
	)
	(via
		(at 167.252142 -410.664152)
		(size 0.4572)
		(drill 0.254)
		(layers "F.Cu" "B.Cu")
		(net "GND")
	)
	(via
		(at 460.664814 -220.266768)
		(size 0.4572)
		(drill 0.2032)
		(layers "F.Cu" "B.Cu")
		(net "GND")
	)
	(via
		(at 52.298346 -201.56678)
		(size 0.4572)
		(drill 0.2032)
		(layers "F.Cu" "B.Cu")
		(net "GND")
	)
	(via
		(at 124.907294 -289.807142)
		(size 0.4572)
		(drill 0.2032)
		(layers "F.Cu" "B.Cu")
		(net "GND")
	)
	(via
		(at 325.15429 -340.360508)
		(size 0.508)
		(drill 0.254)
		(layers "F.Cu" "B.Cu")
		(net "GND")
	)
	(via
		(at 339.014562 -276.708616)
		(size 0.4572)
		(drill 0.2032)
		(layers "F.Cu" "B.Cu")
		(net "GND")
	)
	(via
		(at 62.051946 -227.066602)
		(size 0.4572)
		(drill 0.2032)
		(layers "F.Cu" "B.Cu")
		(net "GND")
	)
	(via
		(at 337.581494 -56.908446)
		(size 0.4572)
		(drill 0.2032)
		(layers "F.Cu" "B.Cu")
		(net "GND")
	)
	(via
		(at 370.38788 -228.45903)
		(size 0.4572)
		(drill 0.2032)
		(layers "F.Cu" "B.Cu")
		(net "GND")
	)
	(via
		(at 419.502082 -297.616626)
		(size 0.4572)
		(drill 0.2032)
		(layers "F.Cu" "B.Cu")
		(net "GND")
	)
	(via
		(at 185.62828 -21.351748)
		(size 0.508)
		(drill 0.254)
		(layers "F.Cu" "B.Cu")
		(net "GND")
	)
	(via
		(at 299.004482 -250.866656)
		(size 0.4572)
		(drill 0.2032)
		(layers "F.Cu" "B.Cu")
		(net "GND")
	)
	(via
		(at 177.633884 -323.434456)
		(size 0.4572)
		(drill 0.2032)
		(layers "F.Cu" "B.Cu")
		(net "GND")
	)
	(via
		(at 255.673606 -99.572318)
		(size 0.508)
		(drill 0.254)
		(layers "F.Cu" "B.Cu")
		(net "GND")
	)
	(via
		(at 305.0413 -404.51786)
		(size 0.4572)
		(drill 0.254)
		(layers "F.Cu" "B.Cu")
		(net "GND")
	)
	(via
		(at 67.250056 -436.347362)
		(size 0.4572)
		(drill 0.2032)
		(layers "F.Cu" "B.Cu")
		(net "GND")
	)
	(via
		(at 30.53715 -128.109472)
		(size 0.508)
		(drill 0.254)
		(layers "F.Cu" "B.Cu")
		(net "GND")
	)
	(via
		(at 82.76717 -57.815226)
		(size 0.508)
		(drill 0.254)
		(layers "F.Cu" "B.Cu")
		(net "GND")
	)
	(via
		(at 210.514946 -197.316598)
		(size 0.4572)
		(drill 0.2032)
		(layers "F.Cu" "B.Cu")
		(net "GND")
	)
	(via
		(at 347.83014 -57.024016)
		(size 0.49022)
		(drill 0.254)
		(layers "F.Cu" "B.Cu")
		(net "GND")
	)
	(via
		(at 58.065162 -159.56788)
		(size 0.508)
		(drill 0.254)
		(layers "F.Cu" "B.Cu")
		(net "GND")
	)
	(via
		(at 35.976814 -202.416664)
		(size 0.4572)
		(drill 0.2032)
		(layers "F.Cu" "B.Cu")
		(net "GND")
	)
	(via
		(at 430.489614 -251.716794)
		(size 0.4572)
		(drill 0.2032)
		(layers "F.Cu" "B.Cu")
		(net "GND")
	)
	(via
		(at 54.724046 -236.416596)
		(size 0.4572)
		(drill 0.2032)
		(layers "F.Cu" "B.Cu")
		(net "GND")
	)
	(via
		(at 200.58888 -147.792948)
		(size 0.508)
		(drill 0.254)
		(layers "F.Cu" "B.Cu")
		(net "GND")
	)
	(via
		(at 334.053688 -403.883876)
		(size 0.4064)
		(drill 0.2032)
		(layers "F.Cu" "B.Cu")
		(net "GND")
	)
	(via
		(at 9.245346 -206.666592)
		(size 0.4572)
		(drill 0.2032)
		(layers "F.Cu" "B.Cu")
		(net "GND")
	)
	(via
		(at 29.666946 -267.016738)
		(size 0.4572)
		(drill 0.2032)
		(layers "F.Cu" "B.Cu")
		(net "GND")
	)
	(via
		(at 165.252146 -281.466798)
		(size 0.4572)
		(drill 0.2032)
		(layers "F.Cu" "B.Cu")
		(net "GND")
	)
	(via
		(at 266.619482 -233.86669)
		(size 0.4572)
		(drill 0.2032)
		(layers "F.Cu" "B.Cu")
		(net "GND")
	)
	(via
		(at 45.179234 -109.444282)
		(size 0.508)
		(drill 0.254)
		(layers "F.Cu" "B.Cu")
		(net "GND")
	)
	(via
		(at 325.793862 -68.439284)
		(size 0.508)
		(drill 0.254)
		(layers "F.Cu" "B.Cu")
		(net "GND")
	)
	(via
		(at 56.398414 -202.416664)
		(size 0.4572)
		(drill 0.2032)
		(layers "F.Cu" "B.Cu")
		(net "GND")
	)
	(via
		(at 413.986218 -149.972776)
		(size 0.508)
		(drill 0.254)
		(layers "F.Cu" "B.Cu")
		(net "GND")
	)
	(via
		(at 259.075682 -291.666676)
		(size 0.4572)
		(drill 0.2032)
		(layers "F.Cu" "B.Cu")
		(net "GND")
	)
	(via
		(at 138.0363 -149.926548)
		(size 0.508)
		(drill 0.254)
		(layers "F.Cu" "B.Cu")
		(net "GND")
	)
	(via
		(at 61.250068 -436.051198)
		(size 0.4572)
		(drill 0.2032)
		(layers "F.Cu" "B.Cu")
		(net "GND")
	)
	(via
		(at 276.373082 -303.566576)
		(size 0.4572)
		(drill 0.2032)
		(layers "F.Cu" "B.Cu")
		(net "GND")
	)
	(via
		(at 264.729214 -273.816572)
		(size 0.4572)
		(drill 0.2032)
		(layers "F.Cu" "B.Cu")
		(net "GND")
	)
	(via
		(at 400.053302 -401.492212)
		(size 0.4572)
		(drill 0.254)
		(layers "F.Cu" "B.Cu")
		(net "GND")
	)
	(via
		(at 113.072418 -335.704434)
		(size 0.49022)
		(drill 0.254)
		(layers "F.Cu" "B.Cu")
		(net "GND")
	)
	(via
		(at 127.430022 -407.638504)
		(size 0.4572)
		(drill 0.254)
		(layers "F.Cu" "B.Cu")
		(net "GND")
	)
	(via
		(at 304.338482 -245.76659)
		(size 0.4572)
		(drill 0.2032)
		(layers "F.Cu" "B.Cu")
		(net "GND")
	)
	(via
		(at 345.593162 -271.825212)
		(size 0.4572)
		(drill 0.2032)
		(layers "F.Cu" "B.Cu")
		(net "GND")
	)
	(via
		(at 210.514946 -234.716574)
		(size 0.4572)
		(drill 0.2032)
		(layers "F.Cu" "B.Cu")
		(net "GND")
	)
	(via
		(at 184.439814 -278.916638)
		(size 0.4572)
		(drill 0.2032)
		(layers "F.Cu" "B.Cu")
		(net "GND")
	)
	(via
		(at 138.239754 -410.030168)
		(size 0.4064)
		(drill 0.2032)
		(layers "F.Cu" "B.Cu")
		(net "GND")
	)
	(via
		(at 417.292282 -211.766658)
		(size 0.4572)
		(drill 0.2032)
		(layers "F.Cu" "B.Cu")
		(net "GND")
	)
	(via
		(at 124.366782 -409.396184)
		(size 0.4572)
		(drill 0.254)
		(layers "F.Cu" "B.Cu")
		(net "GND")
	)
	(via
		(at 349.27286 -406.34666)
		(size 0.4572)
		(drill 0.254)
		(layers "F.Cu" "B.Cu")
		(net "GND")
	)
	(via
		(at 159.918146 -210.916774)
		(size 0.4572)
		(drill 0.2032)
		(layers "F.Cu" "B.Cu")
		(net "GND")
	)
	(via
		(at 24.332946 -248.31675)
		(size 0.4572)
		(drill 0.2032)
		(layers "F.Cu" "B.Cu")
		(net "GND")
	)
	(via
		(at 347.003116 -257.98907)
		(size 0.4572)
		(drill 0.2032)
		(layers "F.Cu" "B.Cu")
		(net "GND")
	)
	(via
		(at 356.373684 -256.330196)
		(size 0.4572)
		(drill 0.2032)
		(layers "F.Cu" "B.Cu")
		(net "GND")
	)
	(via
		(at 118.433088 -242.96116)
		(size 0.4572)
		(drill 0.2032)
		(layers "F.Cu" "B.Cu")
		(net "GND")
	)
	(via
		(at 299.004482 -224.516696)
		(size 0.4572)
		(drill 0.2032)
		(layers "F.Cu" "B.Cu")
		(net "GND")
	)
	(via
		(at 330.99248 -77.257148)
		(size 0.508)
		(drill 0.254)
		(layers "F.Cu" "B.Cu")
		(net "GND")
	)
	(via
		(at 121.508266 -223.575626)
		(size 0.4572)
		(drill 0.2032)
		(layers "F.Cu" "B.Cu")
		(net "GND")
	)
	(via
		(at 20.889214 -216.866724)
		(size 0.4572)
		(drill 0.2032)
		(layers "F.Cu" "B.Cu")
		(net "GND")
	)
	(via
		(at 425.156884 -360.937556)
		(size 0.49022)
		(drill 0.254)
		(layers "F.Cu" "B.Cu")
		(net "GND")
	)
	(via
		(at 184.155588 -121.375424)
		(size 0.4572)
		(drill 0.254)
		(layers "F.Cu" "B.Cu")
		(net "GND")
	)
	(via
		(at 100.942394 -287.28924)
		(size 0.4572)
		(drill 0.2032)
		(layers "F.Cu" "B.Cu")
		(net "GND")
	)
	(via
		(at 449.71208 -93.509592)
		(size 0.508)
		(drill 0.254)
		(layers "F.Cu" "B.Cu")
		(net "GND")
	)
	(via
		(at 164.018214 -200.716642)
		(size 0.4572)
		(drill 0.2032)
		(layers "F.Cu" "B.Cu")
		(net "GND")
	)
	(via
		(at 22.123146 -246.616728)
		(size 0.4572)
		(drill 0.2032)
		(layers "F.Cu" "B.Cu")
		(net "GND")
	)
	(via
		(at 307.566314 -285.716726)
		(size 0.4572)
		(drill 0.2032)
		(layers "F.Cu" "B.Cu")
		(net "GND")
	)
	(via
		(at 445.577214 -223.666558)
		(size 0.4572)
		(drill 0.2032)
		(layers "F.Cu" "B.Cu")
		(net "GND")
	)
	(via
		(at 460.664814 -265.316716)
		(size 0.4572)
		(drill 0.2032)
		(layers "F.Cu" "B.Cu")
		(net "GND")
	)
	(via
		(at 435.823614 -278.066754)
		(size 0.4572)
		(drill 0.2032)
		(layers "F.Cu" "B.Cu")
		(net "GND")
	)
	(via
		(at 349.242634 -235.783882)
		(size 0.4572)
		(drill 0.2032)
		(layers "F.Cu" "B.Cu")
		(net "GND")
	)
	(via
		(at 447.467482 -261.066788)
		(size 0.4572)
		(drill 0.2032)
		(layers "F.Cu" "B.Cu")
		(net "GND")
	)
	(via
		(at 445.577214 -289.11677)
		(size 0.4572)
		(drill 0.2032)
		(layers "F.Cu" "B.Cu")
		(net "GND")
	)
	(via
		(at 339.37448 -241.481102)
		(size 0.4572)
		(drill 0.2032)
		(layers "F.Cu" "B.Cu")
		(net "GND")
	)
	(via
		(at 54.333648 -155.60167)
		(size 0.49022)
		(drill 0.254)
		(layers "F.Cu" "B.Cu")
		(net "GND")
	)
	(via
		(at 66.367914 -207.51673)
		(size 0.4572)
		(drill 0.2032)
		(layers "F.Cu" "B.Cu")
		(net "GND")
	)
	(via
		(at 389.604758 -404.51786)
		(size 0.4572)
		(drill 0.254)
		(layers "F.Cu" "B.Cu")
		(net "GND")
	)
	(via
		(at 343.911428 -326.910192)
		(size 0.508)
		(drill 0.254)
		(layers "F.Cu" "B.Cu")
		(net "GND")
	)
	(via
		(at 335.14538 -242.294918)
		(size 0.4572)
		(drill 0.2032)
		(layers "F.Cu" "B.Cu")
		(net "GND")
	)
	(via
		(at 319.098676 -404.51786)
		(size 0.4572)
		(drill 0.254)
		(layers "F.Cu" "B.Cu")
		(net "GND")
	)
	(via
		(at 394.899642 -63.23203)
		(size 0.508)
		(drill 0.254)
		(layers "F.Cu" "B.Cu")
		(net "GND")
	)
	(via
		(at 258.447794 -109.229652)
		(size 0.508)
		(drill 0.254)
		(layers "F.Cu" "B.Cu")
		(net "GND")
	)
	(via
		(at 398.731232 -4.317746)
		(size 0.508)
		(drill 0.254)
		(layers "F.Cu" "B.Cu")
		(net "GND")
	)
	(via
		(at 46.376082 -18.502376)
		(size 0.508)
		(drill 0.254)
		(layers "F.Cu" "B.Cu")
		(net "GND")
	)
	(via
		(at 209.281014 -213.46668)
		(size 0.4572)
		(drill 0.2032)
		(layers "F.Cu" "B.Cu")
		(net "GND")
	)
	(via
		(at 385.064762 -263.686544)
		(size 0.4318)
		(drill 0.2032)
		(layers "F.Cu" "B.Cu")
		(net "GND")
	)
	(via
		(at 276.373082 -261.066788)
		(size 0.4572)
		(drill 0.2032)
		(layers "F.Cu" "B.Cu")
		(net "GND")
	)
	(via
		(at 128.35001 -439.651394)
		(size 0.4572)
		(drill 0.2032)
		(layers "F.Cu" "B.Cu")
		(net "GND")
	)
	(via
		(at 69.250052 -426.54728)
		(size 0.4572)
		(drill 0.2032)
		(layers "F.Cu" "B.Cu")
		(net "GND")
	)
	(via
		(at 357.810562 -275.08073)
		(size 0.4572)
		(drill 0.2032)
		(layers "F.Cu" "B.Cu")
		(net "GND")
	)
	(via
		(at 69.2404 -6.904228)
		(size 0.508)
		(drill 0.254)
		(layers "F.Cu" "B.Cu")
		(net "GND")
	)
	(via
		(at 104.591866 -226.831144)
		(size 0.4572)
		(drill 0.2032)
		(layers "F.Cu" "B.Cu")
		(net "GND")
	)
	(via
		(at 287.360614 -199.01662)
		(size 0.4572)
		(drill 0.2032)
		(layers "F.Cu" "B.Cu")
		(net "GND")
	)
	(via
		(at 11.135614 -247.466612)
		(size 0.4572)
		(drill 0.2032)
		(layers "F.Cu" "B.Cu")
		(net "GND")
	)
	(via
		(at 351.701862 -267.755878)
		(size 0.4572)
		(drill 0.2032)
		(layers "F.Cu" "B.Cu")
		(net "GND")
	)
	(via
		(at 450.911214 -300.166786)
		(size 0.4572)
		(drill 0.2032)
		(layers "F.Cu" "B.Cu")
		(net "GND")
	)
	(via
		(at 434.589682 -258.516628)
		(size 0.4572)
		(drill 0.2032)
		(layers "F.Cu" "B.Cu")
		(net "GND")
	)
	(via
		(at 272.273014 -248.31675)
		(size 0.4572)
		(drill 0.2032)
		(layers "F.Cu" "B.Cu")
		(net "GND")
	)
	(via
		(at 370.968016 -281.59202)
		(size 0.4572)
		(drill 0.2032)
		(layers "F.Cu" "B.Cu")
		(net "GND")
	)
	(via
		(at 199.527414 -306.96662)
		(size 0.4572)
		(drill 0.2032)
		(layers "F.Cu" "B.Cu")
		(net "GND")
	)
	(via
		(at 421.89146 -360.735372)
		(size 0.508)
		(drill 0.254)
		(layers "F.Cu" "B.Cu")
		(net "GND")
	)
	(via
		(at 380.256034 -226.017328)
		(size 0.4572)
		(drill 0.2032)
		(layers "F.Cu" "B.Cu")
		(net "GND")
	)
	(via
		(at 346.42298 -237.411514)
		(size 0.4572)
		(drill 0.2032)
		(layers "F.Cu" "B.Cu")
		(net "GND")
	)
	(via
		(at 212.724746 -268.71676)
		(size 0.4572)
		(drill 0.2032)
		(layers "F.Cu" "B.Cu")
		(net "GND")
	)
	(via
		(at 121.23293 -335.704434)
		(size 0.49022)
		(drill 0.254)
		(layers "F.Cu" "B.Cu")
		(net "GND")
	)
	(via
		(at 131.846066 -244.73662)
		(size 0.4572)
		(drill 0.2032)
		(layers "F.Cu" "B.Cu")
		(net "GND")
	)
	(via
		(at 455.011282 -233.86669)
		(size 0.4572)
		(drill 0.2032)
		(layers "F.Cu" "B.Cu")
		(net "GND")
	)
	(via
		(at 445.577214 -313.766708)
		(size 0.4572)
		(drill 0.2032)
		(layers "F.Cu" "B.Cu")
		(net "GND")
	)
	(via
		(at 110.483396 -358.848406)
		(size 0.508)
		(drill 0.254)
		(layers "F.Cu" "B.Cu")
		(net "GND")
	)
	(via
		(at 445.577214 -307.816758)
		(size 0.4572)
		(drill 0.2032)
		(layers "F.Cu" "B.Cu")
		(net "GND")
	)
	(via
		(at 313.265058 -323.72681)
		(size 0.4572)
		(drill 0.2032)
		(layers "F.Cu" "B.Cu")
		(net "GND")
	)
	(via
		(at 304.338482 -205.816708)
		(size 0.4572)
		(drill 0.2032)
		(layers "F.Cu" "B.Cu")
		(net "GND")
	)
	(via
		(at 361.929934 -217.064336)
		(size 0.4572)
		(drill 0.2032)
		(layers "F.Cu" "B.Cu")
		(net "GND")
	)
	(via
		(at 344.07348 -233.34218)
		(size 0.4572)
		(drill 0.2032)
		(layers "F.Cu" "B.Cu")
		(net "GND")
	)
	(via
		(at 128.35001 -436.051198)
		(size 0.4572)
		(drill 0.2032)
		(layers "F.Cu" "B.Cu")
		(net "GND")
	)
	(via
		(at 151.349964 -430.299622)
		(size 0.4572)
		(drill 0.2032)
		(layers "F.Cu" "B.Cu")
		(net "GND")
	)
	(via
		(at 262.519414 -311.216802)
		(size 0.4572)
		(drill 0.2032)
		(layers "F.Cu" "B.Cu")
		(net "GND")
	)
	(via
		(at 150.76043 -124.005848)
		(size 0.508)
		(drill 0.254)
		(layers "F.Cu" "B.Cu")
		(net "GND")
	)
	(via
		(at 243.0018 -199.862948)
		(size 0.508)
		(drill 0.254)
		(layers "F.Cu" "B.Cu")
		(net "GND")
	)
	(via
		(at 120.678194 -280.778204)
		(size 0.4572)
		(drill 0.2032)
		(layers "F.Cu" "B.Cu")
		(net "GND")
	)
	(via
		(at 368.542824 -335.704434)
		(size 0.49022)
		(drill 0.254)
		(layers "F.Cu" "B.Cu")
		(net "GND")
	)
	(via
		(at 187.883546 -210.916774)
		(size 0.4572)
		(drill 0.2032)
		(layers "F.Cu" "B.Cu")
		(net "GND")
	)
	(via
		(at 257.8862 -37.778944)
		(size 0.508)
		(drill 0.254)
		(layers "F.Cu" "B.Cu")
		(net "GND")
	)
	(via
		(at 62.907418 -261.10565)
		(size 0.6604)
		(drill 0.3302)
		(layers "F.Cu" "B.Cu")
		(net "GND")
	)
	(via
		(at 411.958282 -239.81664)
		(size 0.4572)
		(drill 0.2032)
		(layers "F.Cu" "B.Cu")
		(net "GND")
	)
	(via
		(at 302.448214 -258.516628)
		(size 0.4572)
		(drill 0.2032)
		(layers "F.Cu" "B.Cu")
		(net "GND")
	)
	(via
		(at 392.209782 -410.664152)
		(size 0.4572)
		(drill 0.254)
		(layers "F.Cu" "B.Cu")
		(net "GND")
	)
	(via
		(at 420.736014 -240.666778)
		(size 0.4572)
		(drill 0.2032)
		(layers "F.Cu" "B.Cu")
		(net "GND")
	)
	(via
		(at 352.2218 -335.704434)
		(size 0.49022)
		(drill 0.254)
		(layers "F.Cu" "B.Cu")
		(net "GND")
	)
	(via
		(at 171.562014 -249.166634)
		(size 0.4572)
		(drill 0.2032)
		(layers "F.Cu" "B.Cu")
		(net "GND")
	)
	(via
		(at 338.904834 -219.506038)
		(size 0.4572)
		(drill 0.2032)
		(layers "F.Cu" "B.Cu")
		(net "GND")
	)
	(via
		(at 49.170082 -18.246344)
		(size 0.508)
		(drill 0.254)
		(layers "F.Cu" "B.Cu")
		(net "GND")
	)
	(via
		(at 21.911056 -6.597396)
		(size 0.508)
		(drill 0.254)
		(layers "F.Cu" "B.Cu")
		(net "GND")
	)
	(via
		(at 306.548282 -198.166736)
		(size 0.4572)
		(drill 0.2032)
		(layers "F.Cu" "B.Cu")
		(net "GND")
	)
	(via
		(at 171.562014 -194.766692)
		(size 0.4572)
		(drill 0.2032)
		(layers "F.Cu" "B.Cu")
		(net "GND")
	)
	(via
		(at 136.349994 -436.051198)
		(size 0.4572)
		(drill 0.2032)
		(layers "F.Cu" "B.Cu")
		(net "GND")
	)
	(via
		(at 197.637146 -273.816572)
		(size 0.4572)
		(drill 0.2032)
		(layers "F.Cu" "B.Cu")
		(net "GND")
	)
	(via
		(at 358.170734 -223.575626)
		(size 0.4572)
		(drill 0.2032)
		(layers "F.Cu" "B.Cu")
		(net "GND")
	)
	(via
		(at 421.92194 -110.280958)
		(size 0.508)
		(drill 0.254)
		(layers "F.Cu" "B.Cu")
		(net "GND")
	)
	(via
		(at 337.96478 -247.178322)
		(size 0.4572)
		(drill 0.2032)
		(layers "F.Cu" "B.Cu")
		(net "GND")
	)
	(via
		(at 458.455014 -206.666592)
		(size 0.4572)
		(drill 0.2032)
		(layers "F.Cu" "B.Cu")
		(net "GND")
	)
	(via
		(at 40.533828 -4.328668)
		(size 0.508)
		(drill 0.254)
		(layers "F.Cu" "B.Cu")
		(net "GND")
	)
	(via
		(at 348.470474 -174.060612)
		(size 0.508)
		(drill 0.254)
		(layers "F.Cu" "B.Cu")
		(net "GND")
	)
	(via
		(at 87.675466 -233.34218)
		(size 0.4572)
		(drill 0.2032)
		(layers "F.Cu" "B.Cu")
		(net "GND")
	)
	(via
		(at 132.315966 -222.761556)
		(size 0.4572)
		(drill 0.2032)
		(layers "F.Cu" "B.Cu")
		(net "GND")
	)
	(via
		(at 408.374596 -17.601438)
		(size 0.508)
		(drill 0.254)
		(layers "F.Cu" "B.Cu")
		(net "GND")
	)
	(via
		(at 352.062034 -230.900478)
		(size 0.4572)
		(drill 0.2032)
		(layers "F.Cu" "B.Cu")
		(net "GND")
	)
	(via
		(at 291.460682 -272.966688)
		(size 0.4572)
		(drill 0.2032)
		(layers "F.Cu" "B.Cu")
		(net "GND")
	)
	(via
		(at 58.824114 -219.41663)
		(size 0.4572)
		(drill 0.2032)
		(layers "F.Cu" "B.Cu")
		(net "GND")
	)
	(via
		(at 355.461062 -280.778204)
		(size 0.4572)
		(drill 0.2032)
		(layers "F.Cu" "B.Cu")
		(net "GND")
	)
	(via
		(at 317.655448 -400.858228)
		(size 0.4064)
		(drill 0.2032)
		(layers "F.Cu" "B.Cu")
		(net "GND")
	)
	(via
		(at 413.192214 -229.616762)
		(size 0.4572)
		(drill 0.2032)
		(layers "F.Cu" "B.Cu")
		(net "GND")
	)
	(via
		(at 184.439814 -303.566576)
		(size 0.4572)
		(drill 0.2032)
		(layers "F.Cu" "B.Cu")
		(net "GND")
	)
	(via
		(at 335.699608 -50.450496)
		(size 0.4572)
		(drill 0.2032)
		(layers "F.Cu" "B.Cu")
		(net "GND")
	)
	(via
		(at 433.690776 -103.38943)
		(size 0.508)
		(drill 0.254)
		(layers "F.Cu" "B.Cu")
		(net "GND")
	)
	(via
		(at 92.844112 -245.55069)
		(size 0.4572)
		(drill 0.2032)
		(layers "F.Cu" "B.Cu")
		(net "GND")
	)
	(via
		(at 380.365762 -257.175254)
		(size 0.4572)
		(drill 0.2032)
		(layers "F.Cu" "B.Cu")
		(net "GND")
	)
	(via
		(at 121.774458 -201.48677)
		(size 0.6604)
		(drill 0.3302)
		(layers "F.Cu" "B.Cu")
		(net "GND")
	)
	(via
		(at 135.714994 -279.150318)
		(size 0.4572)
		(drill 0.2032)
		(layers "F.Cu" "B.Cu")
		(net "GND")
	)
	(via
		(at 159.918146 -201.56678)
		(size 0.4572)
		(drill 0.2032)
		(layers "F.Cu" "B.Cu")
		(net "GND")
	)
	(via
		(at 415.402014 -260.21665)
		(size 0.4572)
		(drill 0.2032)
		(layers "F.Cu" "B.Cu")
		(net "GND")
	)
	(via
		(at 350.182434 -216.25052)
		(size 0.4572)
		(drill 0.2032)
		(layers "F.Cu" "B.Cu")
		(net "GND")
	)
	(via
		(at 120.678194 -284.033722)
		(size 0.4572)
		(drill 0.2032)
		(layers "F.Cu" "B.Cu")
		(net "GND")
	)
	(via
		(at 434.589682 -211.766658)
		(size 0.4572)
		(drill 0.2032)
		(layers "F.Cu" "B.Cu")
		(net "GND")
	)
	(via
		(at 37.210746 -236.416596)
		(size 0.4572)
		(drill 0.2032)
		(layers "F.Cu" "B.Cu")
		(net "GND")
	)
	(via
		(at 31.876746 -281.466798)
		(size 0.4572)
		(drill 0.2032)
		(layers "F.Cu" "B.Cu")
		(net "GND")
	)
	(via
		(at 13.345414 -267.866622)
		(size 0.4572)
		(drill 0.2032)
		(layers "F.Cu" "B.Cu")
		(net "GND")
	)
	(via
		(at 401.399502 -409.396184)
		(size 0.4572)
		(drill 0.254)
		(layers "F.Cu" "B.Cu")
		(net "GND")
	)
	(via
		(at 411.52318 -176.367948)
		(size 0.508)
		(drill 0.254)
		(layers "F.Cu" "B.Cu")
		(net "GND")
	)
	(via
		(at 257.185414 -246.616728)
		(size 0.4572)
		(drill 0.2032)
		(layers "F.Cu" "B.Cu")
		(net "GND")
	)
	(via
		(at 46.964346 -197.316598)
		(size 0.4572)
		(drill 0.2032)
		(layers "F.Cu" "B.Cu")
		(net "GND")
	)
	(via
		(at 314.092082 -204.116686)
		(size 0.4572)
		(drill 0.2032)
		(layers "F.Cu" "B.Cu")
		(net "GND")
	)
	(via
		(at 435.823614 -195.616576)
		(size 0.4572)
		(drill 0.2032)
		(layers "F.Cu" "B.Cu")
		(net "GND")
	)
	(via
		(at 88.950546 -407.638504)
		(size 0.4572)
		(drill 0.254)
		(layers "F.Cu" "B.Cu")
		(net "GND")
	)
	(via
		(at 427.512734 -183.428132)
		(size 0.508)
		(drill 0.254)
		(layers "F.Cu" "B.Cu")
		(net "GND")
	)
	(via
		(at 88.724994 -267.755878)
		(size 0.4572)
		(drill 0.2032)
		(layers "F.Cu" "B.Cu")
		(net "GND")
	)
	(via
		(at 110.23092 -249.620278)
		(size 0.4572)
		(drill 0.2032)
		(layers "F.Cu" "B.Cu")
		(net "GND")
	)
	(via
		(at 15.959582 -104.151938)
		(size 0.508)
		(drill 0.254)
		(layers "F.Cu" "B.Cu")
		(net "GND")
	)
	(via
		(at 411.52318 -167.731948)
		(size 0.508)
		(drill 0.254)
		(layers "F.Cu" "B.Cu")
		(net "GND")
	)
	(via
		(at 86.735666 -231.714548)
		(size 0.4318)
		(drill 0.2032)
		(layers "F.Cu" "B.Cu")
		(net "GND")
	)
	(via
		(at 132.785612 -236.597952)
		(size 0.4572)
		(drill 0.2032)
		(layers "F.Cu" "B.Cu")
		(net "GND")
	)
	(via
		(at 186.649614 -233.86669)
		(size 0.4572)
		(drill 0.2032)
		(layers "F.Cu" "B.Cu")
		(net "GND")
	)
	(via
		(at 44.754546 -246.616728)
		(size 0.4572)
		(drill 0.2032)
		(layers "F.Cu" "B.Cu")
		(net "GND")
	)
	(via
		(at 165.252146 -298.466764)
		(size 0.4572)
		(drill 0.2032)
		(layers "F.Cu" "B.Cu")
		(net "GND")
	)
	(via
		(at 56.182514 -210.066636)
		(size 0.4572)
		(drill 0.2032)
		(layers "F.Cu" "B.Cu")
		(net "GND")
	)
	(via
		(at 338.434934 -234.970066)
		(size 0.4572)
		(drill 0.2032)
		(layers "F.Cu" "B.Cu")
		(net "GND")
	)
	(via
		(at 78.250034 -433.747164)
		(size 0.4572)
		(drill 0.2032)
		(layers "F.Cu" "B.Cu")
		(net "GND")
	)
	(via
		(at 368.978434 -222.761556)
		(size 0.4572)
		(drill 0.2032)
		(layers "F.Cu" "B.Cu")
		(net "GND")
	)
	(via
		(at 334.414876 -403.249892)
		(size 0.4572)
		(drill 0.254)
		(layers "F.Cu" "B.Cu")
		(net "GND")
	)
	(via
		(at 43.520614 -275.516594)
		(size 0.4572)
		(drill 0.2032)
		(layers "F.Cu" "B.Cu")
		(net "GND")
	)
	(via
		(at 424.836082 -196.466714)
		(size 0.4572)
		(drill 0.2032)
		(layers "F.Cu" "B.Cu")
		(net "GND")
	)
	(via
		(at 288.094166 -361.625388)
		(size 0.49022)
		(drill 0.254)
		(layers "F.Cu" "B.Cu")
		(net "GND")
	)
	(via
		(at 116.415058 -331.87132)
		(size 0.508)
		(drill 0.254)
		(layers "F.Cu" "B.Cu")
		(net "GND")
	)
	(via
		(at 72.124062 -38.735762)
		(size 0.508)
		(drill 0.254)
		(layers "F.Cu" "B.Cu")
		(net "GND")
	)
	(via
		(at 261.285482 -289.966654)
		(size 0.4572)
		(drill 0.2032)
		(layers "F.Cu" "B.Cu")
		(net "GND")
	)
	(via
		(at 136.184894 -278.336502)
		(size 0.4572)
		(drill 0.2032)
		(layers "F.Cu" "B.Cu")
		(net "GND")
	)
	(via
		(at 368.727228 -331.776832)
		(size 0.49022)
		(drill 0.254)
		(layers "F.Cu" "B.Cu")
		(net "GND")
	)
	(via
		(at 103.291894 -281.59202)
		(size 0.4572)
		(drill 0.2032)
		(layers "F.Cu" "B.Cu")
		(net "GND")
	)
	(via
		(at 14.579346 -295.06672)
		(size 0.4572)
		(drill 0.2032)
		(layers "F.Cu" "B.Cu")
		(net "GND")
	)
	(via
		(at 407.858214 -233.016806)
		(size 0.4572)
		(drill 0.2032)
		(layers "F.Cu" "B.Cu")
		(net "GND")
	)
	(via
		(at 37.210746 -307.816758)
		(size 0.4572)
		(drill 0.2032)
		(layers "F.Cu" "B.Cu")
		(net "GND")
	)
	(via
		(at 294.904414 -231.316784)
		(size 0.4572)
		(drill 0.2032)
		(layers "F.Cu" "B.Cu")
		(net "GND")
	)
	(via
		(at 186.649614 -271.266666)
		(size 0.4572)
		(drill 0.2032)
		(layers "F.Cu" "B.Cu")
		(net "GND")
	)
	(via
		(at 413.996886 -165.727126)
		(size 0.508)
		(drill 0.254)
		(layers "F.Cu" "B.Cu")
		(net "GND")
	)
	(via
		(at 168.854628 -350.832928)
		(size 0.508)
		(drill 0.254)
		(layers "F.Cu" "B.Cu")
		(net "GND")
	)
	(via
		(at 403.349968 -432.747166)
		(size 0.4572)
		(drill 0.2032)
		(layers "F.Cu" "B.Cu")
		(net "GND")
	)
	(via
		(at 19.284188 -395.344396)
		(size 0.508)
		(drill 0.254)
		(layers "F.Cu" "B.Cu")
		(net "GND")
	)
	(via
		(at 125.625606 -409.396184)
		(size 0.4572)
		(drill 0.254)
		(layers "F.Cu" "B.Cu")
		(net "GND")
	)
	(via
		(at 286.260032 -393.77239)
		(size 0.508)
		(drill 0.254)
		(layers "F.Cu" "B.Cu")
		(net "GND")
	)
	(via
		(at 165.252146 -265.316716)
		(size 0.4572)
		(drill 0.2032)
		(layers "F.Cu" "B.Cu")
		(net "GND")
	)
	(via
		(at 159.422084 -323.383656)
		(size 0.4572)
		(drill 0.2032)
		(layers "F.Cu" "B.Cu")
		(net "GND")
	)
	(via
		(at 135.135366 -227.64496)
		(size 0.4572)
		(drill 0.2032)
		(layers "F.Cu" "B.Cu")
		(net "GND")
	)
	(via
		(at 157.708346 -223.666558)
		(size 0.4572)
		(drill 0.2032)
		(layers "F.Cu" "B.Cu")
		(net "GND")
	)
	(via
		(at 292.694614 -221.96679)
		(size 0.4572)
		(drill 0.2032)
		(layers "F.Cu" "B.Cu")
		(net "GND")
	)
	(via
		(at 368.928904 -249.106944)
		(size 0.4572)
		(drill 0.2032)
		(layers "F.Cu" "B.Cu")
		(net "GND")
	)
	(via
		(at 327.30567 -341.063072)
		(size 0.49022)
		(drill 0.254)
		(layers "F.Cu" "B.Cu")
		(net "GND")
	)
	(via
		(at 44.754546 -317.166752)
		(size 0.4572)
		(drill 0.2032)
		(layers "F.Cu" "B.Cu")
		(net "GND")
	)
	(via
		(at 462.555082 -275.516594)
		(size 0.4572)
		(drill 0.2032)
		(layers "F.Cu" "B.Cu")
		(net "GND")
	)
	(via
		(at 373.67718 -235.783882)
		(size 0.4572)
		(drill 0.2032)
		(layers "F.Cu" "B.Cu")
		(net "GND")
	)
	(via
		(at 13.345414 -269.566644)
		(size 0.4572)
		(drill 0.2032)
		(layers "F.Cu" "B.Cu")
		(net "GND")
	)
	(via
		(at 185.240676 -350.922082)
		(size 0.508)
		(drill 0.254)
		(layers "F.Cu" "B.Cu")
		(net "GND")
	)
	(via
		(at 87.315294 -258.80314)
		(size 0.4318)
		(drill 0.2032)
		(layers "F.Cu" "B.Cu")
		(net "GND")
	)
	(via
		(at 384.015234 -216.25052)
		(size 0.4572)
		(drill 0.2032)
		(layers "F.Cu" "B.Cu")
		(net "GND")
	)
	(via
		(at 292.694614 -283.166566)
		(size 0.4572)
		(drill 0.2032)
		(layers "F.Cu" "B.Cu")
		(net "GND")
	)
	(via
		(at 302.448214 -214.316564)
		(size 0.4572)
		(drill 0.2032)
		(layers "F.Cu" "B.Cu")
		(net "GND")
	)
	(via
		(at 428.279814 -204.96657)
		(size 0.4572)
		(drill 0.2032)
		(layers "F.Cu" "B.Cu")
		(net "GND")
	)
	(via
		(at 274.163282 -266.1666)
		(size 0.4572)
		(drill 0.2032)
		(layers "F.Cu" "B.Cu")
		(net "GND")
	)
	(via
		(at 54.508146 -223.666558)
		(size 0.4572)
		(drill 0.2032)
		(layers "F.Cu" "B.Cu")
		(net "GND")
	)
	(via
		(at 31.147004 -12.37488)
		(size 0.508)
		(drill 0.254)
		(layers "F.Cu" "B.Cu")
		(net "GND")
	)
	(via
		(at 415.402014 -304.416714)
		(size 0.4572)
		(drill 0.2032)
		(layers "F.Cu" "B.Cu")
		(net "GND")
	)
	(via
		(at 284.778196 -360.054144)
		(size 0.508)
		(drill 0.254)
		(layers "F.Cu" "B.Cu")
		(net "GND")
	)
	(via
		(at 411.349952 -426.69968)
		(size 0.4572)
		(drill 0.2032)
		(layers "F.Cu" "B.Cu")
		(net "GND")
	)
	(via
		(at 424.496484 -360.148378)
		(size 0.49022)
		(drill 0.254)
		(layers "F.Cu" "B.Cu")
		(net "GND")
	)
	(via
		(at 261.285482 -245.76659)
		(size 0.4572)
		(drill 0.2032)
		(layers "F.Cu" "B.Cu")
		(net "GND")
	)
	(via
		(at 126.350014 -437.49976)
		(size 0.4572)
		(drill 0.2032)
		(layers "F.Cu" "B.Cu")
		(net "GND")
	)
	(via
		(at 212.724746 -272.116804)
		(size 0.4572)
		(drill 0.2032)
		(layers "F.Cu" "B.Cu")
		(net "GND")
	)
	(via
		(at 455.011282 -226.216718)
		(size 0.4572)
		(drill 0.2032)
		(layers "F.Cu" "B.Cu")
		(net "GND")
	)
	(via
		(at 41.310814 -266.1666)
		(size 0.4572)
		(drill 0.2032)
		(layers "F.Cu" "B.Cu")
		(net "GND")
	)
	(via
		(at 104.121966 -219.506038)
		(size 0.4572)
		(drill 0.2032)
		(layers "F.Cu" "B.Cu")
		(net "GND")
	)
	(via
		(at 94.723712 -239.0394)
		(size 0.4572)
		(drill 0.2032)
		(layers "F.Cu" "B.Cu")
		(net "GND")
	)
	(via
		(at 384.737102 -404.51786)
		(size 0.4572)
		(drill 0.254)
		(layers "F.Cu" "B.Cu")
		(net "GND")
	)
	(via
		(at 179.105814 -226.216718)
		(size 0.4572)
		(drill 0.2032)
		(layers "F.Cu" "B.Cu")
		(net "GND")
	)
	(via
		(at 259.075682 -312.91657)
		(size 0.4572)
		(drill 0.2032)
		(layers "F.Cu" "B.Cu")
		(net "GND")
	)
	(via
		(at 356.62616 -330.42352)
		(size 0.508)
		(drill 0.254)
		(layers "F.Cu" "B.Cu")
		(net "GND")
	)
	(via
		(at 39.420546 -279.766776)
		(size 0.4572)
		(drill 0.2032)
		(layers "F.Cu" "B.Cu")
		(net "GND")
	)
	(via
		(at 345.15171 -43.350434)
		(size 0.4572)
		(drill 0.2032)
		(layers "F.Cu" "B.Cu")
		(net "GND")
	)
	(via
		(at 51.064414 -196.466714)
		(size 0.4572)
		(drill 0.2032)
		(layers "F.Cu" "B.Cu")
		(net "GND")
	)
	(via
		(at 41.533572 -352.397822)
		(size 0.49022)
		(drill 0.254)
		(layers "F.Cu" "B.Cu")
		(net "GND")
	)
	(via
		(at 417.292282 -308.666642)
		(size 0.4572)
		(drill 0.2032)
		(layers "F.Cu" "B.Cu")
		(net "GND")
	)
	(via
		(at 286.458152 -354.870004)
		(size 0.508)
		(drill 0.254)
		(layers "F.Cu" "B.Cu")
		(net "GND")
	)
	(via
		(at 105.12679 -332.56601)
		(size 0.49022)
		(drill 0.254)
		(layers "F.Cu" "B.Cu")
		(net "GND")
	)
	(via
		(at 333.564484 -73.058274)
		(size 0.508)
		(drill 0.254)
		(layers "F.Cu" "B.Cu")
		(net "GND")
	)
	(via
		(at 201.737214 -202.416664)
		(size 0.4572)
		(drill 0.2032)
		(layers "F.Cu" "B.Cu")
		(net "GND")
	)
	(via
		(at 180.339746 -278.066754)
		(size 0.4572)
		(drill 0.2032)
		(layers "F.Cu" "B.Cu")
		(net "GND")
	)
	(via
		(at 418.432742 -400.224244)
		(size 0.4572)
		(drill 0.254)
		(layers "F.Cu" "B.Cu")
		(net "GND")
	)
	(via
		(at 191.983614 -278.916638)
		(size 0.4572)
		(drill 0.2032)
		(layers "F.Cu" "B.Cu")
		(net "GND")
	)
	(via
		(at 371.32768 -244.73662)
		(size 0.4572)
		(drill 0.2032)
		(layers "F.Cu" "B.Cu")
		(net "GND")
	)
	(via
		(at 99.422966 -222.761556)
		(size 0.4572)
		(drill 0.2032)
		(layers "F.Cu" "B.Cu")
		(net "GND")
	)
	(via
		(at 191.983614 -207.51673)
		(size 0.4572)
		(drill 0.2032)
		(layers "F.Cu" "B.Cu")
		(net "GND")
	)
	(via
		(at 182.549546 -311.216802)
		(size 0.4572)
		(drill 0.2032)
		(layers "F.Cu" "B.Cu")
		(net "GND")
	)
	(via
		(at 153.24836 -52.868068)
		(size 0.508)
		(drill 0.254)
		(layers "F.Cu" "B.Cu")
		(net "GND")
	)
	(via
		(at 445.577214 -231.316784)
		(size 0.4572)
		(drill 0.2032)
		(layers "F.Cu" "B.Cu")
		(net "GND")
	)
	(via
		(at 409.349956 -439.651394)
		(size 0.4572)
		(drill 0.2032)
		(layers "F.Cu" "B.Cu")
		(net "GND")
	)
	(via
		(at 37.210746 -283.166566)
		(size 0.4572)
		(drill 0.2032)
		(layers "F.Cu" "B.Cu")
		(net "GND")
	)
	(via
		(at 316.375796 -59.446668)
		(size 0.508)
		(drill 0.254)
		(layers "F.Cu" "B.Cu")
		(net "GND")
	)
	(via
		(at 416.789362 -360.148378)
		(size 0.49022)
		(drill 0.254)
		(layers "F.Cu" "B.Cu")
		(net "GND")
	)
	(via
		(at 283.916882 -219.41663)
		(size 0.4572)
		(drill 0.2032)
		(layers "F.Cu" "B.Cu")
		(net "GND")
	)
	(via
		(at 434.589682 -275.516594)
		(size 0.4572)
		(drill 0.2032)
		(layers "F.Cu" "B.Cu")
		(net "GND")
	)
	(via
		(at 191.983614 -222.816674)
		(size 0.4572)
		(drill 0.2032)
		(layers "F.Cu" "B.Cu")
		(net "GND")
	)
	(via
		(at 197.637146 -240.666778)
		(size 0.4572)
		(drill 0.2032)
		(layers "F.Cu" "B.Cu")
		(net "GND")
	)
	(via
		(at 113.629948 -262.058912)
		(size 0.4572)
		(drill 0.2032)
		(layers "F.Cu" "B.Cu")
		(net "GND")
	)
	(via
		(at 304.338482 -278.916638)
		(size 0.4572)
		(drill 0.2032)
		(layers "F.Cu" "B.Cu")
		(net "GND")
	)
	(via
		(at 409.748482 -306.96662)
		(size 0.4572)
		(drill 0.2032)
		(layers "F.Cu" "B.Cu")
		(net "GND")
	)
	(via
		(at 347.942662 -287.28924)
		(size 0.4572)
		(drill 0.2032)
		(layers "F.Cu" "B.Cu")
		(net "GND")
	)
	(via
		(at 256.21488 -126.583948)
		(size 0.508)
		(drill 0.254)
		(layers "F.Cu" "B.Cu")
		(net "GND")
	)
	(via
		(at 294.417496 -359.513124)
		(size 0.508)
		(drill 0.254)
		(layers "F.Cu" "B.Cu")
		(net "GND")
	)
	(via
		(at 43.520614 -314.616592)
		(size 0.4572)
		(drill 0.2032)
		(layers "F.Cu" "B.Cu")
		(net "GND")
	)
	(via
		(at 257.185414 -240.666778)
		(size 0.4572)
		(drill 0.2032)
		(layers "F.Cu" "B.Cu")
		(net "GND")
	)
	(via
		(at 361.569762 -255.547622)
		(size 0.4572)
		(drill 0.2032)
		(layers "F.Cu" "B.Cu")
		(net "GND")
	)
	(via
		(at 383.185162 -281.59202)
		(size 0.4572)
		(drill 0.2032)
		(layers "F.Cu" "B.Cu")
		(net "GND")
	)
	(via
		(at 207.071214 -249.166634)
		(size 0.4572)
		(drill 0.2032)
		(layers "F.Cu" "B.Cu")
		(net "GND")
	)
	(via
		(at 56.398414 -244.066568)
		(size 0.4572)
		(drill 0.2032)
		(layers "F.Cu" "B.Cu")
		(net "GND")
	)
	(via
		(at 341.213948 -71.92137)
		(size 0.508)
		(drill 0.254)
		(layers "F.Cu" "B.Cu")
		(net "GND")
	)
	(via
		(at 460.336646 -78.418436)
		(size 0.508)
		(drill 0.254)
		(layers "F.Cu" "B.Cu")
		(net "GND")
	)
	(via
		(at 462.555082 -238.116618)
		(size 0.4572)
		(drill 0.2032)
		(layers "F.Cu" "B.Cu")
		(net "GND")
	)
	(via
		(at 96.603566 -219.506038)
		(size 0.4572)
		(drill 0.2032)
		(layers "F.Cu" "B.Cu")
		(net "GND")
	)
	(via
		(at 38.064694 -177.503074)
		(size 0.508)
		(drill 0.254)
		(layers "F.Cu" "B.Cu")
		(net "GND")
	)
	(via
		(at 66.152014 -247.466612)
		(size 0.4572)
		(drill 0.2032)
		(layers "F.Cu" "B.Cu")
		(net "GND")
	)
	(via
		(at 373.787416 -278.336502)
		(size 0.4572)
		(drill 0.2032)
		(layers "F.Cu" "B.Cu")
		(net "GND")
	)
	(via
		(at 124.327412 -241.481102)
		(size 0.4572)
		(drill 0.2032)
		(layers "F.Cu" "B.Cu")
		(net "GND")
	)
	(via
		(at 33.767014 -294.216582)
		(size 0.4572)
		(drill 0.2032)
		(layers "F.Cu" "B.Cu")
		(net "GND")
	)
	(via
		(at 169.352214 -205.816708)
		(size 0.4572)
		(drill 0.2032)
		(layers "F.Cu" "B.Cu")
		(net "GND")
	)
	(via
		(at 287.360614 -227.066602)
		(size 0.4572)
		(drill 0.2032)
		(layers "F.Cu" "B.Cu")
		(net "GND")
	)
	(via
		(at 52.298346 -300.166786)
		(size 0.4572)
		(drill 0.2032)
		(layers "F.Cu" "B.Cu")
		(net "GND")
	)
	(via
		(at 332.250034 -427.851316)
		(size 0.4572)
		(drill 0.2032)
		(layers "F.Cu" "B.Cu")
		(net "GND")
	)
	(via
		(at 413.192214 -298.466764)
		(size 0.4572)
		(drill 0.2032)
		(layers "F.Cu" "B.Cu")
		(net "GND")
	)
	(via
		(at 370.526564 -326.948292)
		(size 0.508)
		(drill 0.254)
		(layers "F.Cu" "B.Cu")
		(net "GND")
	)
	(via
		(at 51.064414 -280.61666)
		(size 0.4572)
		(drill 0.2032)
		(layers "F.Cu" "B.Cu")
		(net "GND")
	)
	(via
		(at 345.483434 -229.272846)
		(size 0.4572)
		(drill 0.2032)
		(layers "F.Cu" "B.Cu")
		(net "GND")
	)
	(via
		(at 55.066946 -9.424924)
		(size 0.508)
		(drill 0.254)
		(layers "F.Cu" "B.Cu")
		(net "GND")
	)
	(via
		(at 424.836082 -221.116652)
		(size 0.4572)
		(drill 0.2032)
		(layers "F.Cu" "B.Cu")
		(net "GND")
	)
	(via
		(at 291.460682 -241.516662)
		(size 0.4572)
		(drill 0.2032)
		(layers "F.Cu" "B.Cu")
		(net "GND")
	)
	(via
		(at 422.945814 -285.716726)
		(size 0.4572)
		(drill 0.2032)
		(layers "F.Cu" "B.Cu")
		(net "GND")
	)
	(via
		(at 332.796134 -243.108988)
		(size 0.4572)
		(drill 0.2032)
		(layers "F.Cu" "B.Cu")
		(net "GND")
	)
	(via
		(at 309.992014 -315.46673)
		(size 0.4572)
		(drill 0.2032)
		(layers "F.Cu" "B.Cu")
		(net "GND")
	)
	(via
		(at 432.379882 -258.516628)
		(size 0.4572)
		(drill 0.2032)
		(layers "F.Cu" "B.Cu")
		(net "GND")
	)
	(via
		(at 432.379882 -221.116652)
		(size 0.4572)
		(drill 0.2032)
		(layers "F.Cu" "B.Cu")
		(net "GND")
	)
	(via
		(at 90.25001 -432.451256)
		(size 0.4572)
		(drill 0.2032)
		(layers "F.Cu" "B.Cu")
		(net "GND")
	)
	(via
		(at 338.904834 -248.806208)
		(size 0.4572)
		(drill 0.2032)
		(layers "F.Cu" "B.Cu")
		(net "GND")
	)
	(via
		(at 28.433014 -244.066568)
		(size 0.4572)
		(drill 0.2032)
		(layers "F.Cu" "B.Cu")
		(net "GND")
	)
	(via
		(at 281.707082 -284.866588)
		(size 0.4572)
		(drill 0.2032)
		(layers "F.Cu" "B.Cu")
		(net "GND")
	)
	(via
		(at 276.373082 -262.76681)
		(size 0.4572)
		(drill 0.2032)
		(layers "F.Cu" "B.Cu")
		(net "GND")
	)
	(via
		(at 101.302312 -229.272846)
		(size 0.4572)
		(drill 0.2032)
		(layers "F.Cu" "B.Cu")
		(net "GND")
	)
	(via
		(at 24.332946 -311.216802)
		(size 0.4572)
		(drill 0.2032)
		(layers "F.Cu" "B.Cu")
		(net "GND")
	)
	(via
		(at 304.09896 -429.621188)
		(size 0.508)
		(drill 0.254)
		(layers "F.Cu" "B.Cu")
		(net "GND")
	)
	(via
		(at 94.254066 -236.597952)
		(size 0.4572)
		(drill 0.2032)
		(layers "F.Cu" "B.Cu")
		(net "GND")
	)
	(via
		(at 387.598158 -76.566776)
		(size 0.6604)
		(drill 0.3302)
		(layers "F.Cu" "B.Cu")
		(net "GND")
	)
	(via
		(at 448.634612 -23.781258)
		(size 0.508)
		(drill 0.254)
		(layers "F.Cu" "B.Cu")
		(net "GND")
	)
	(via
		(at 213.81593 -125.186948)
		(size 0.508)
		(drill 0.254)
		(layers "F.Cu" "B.Cu")
		(net "GND")
	)
	(via
		(at 332.79588 -226.831144)
		(size 0.4572)
		(drill 0.2032)
		(layers "F.Cu" "B.Cu")
		(net "GND")
	)
	(via
		(at 340.894416 -262.058658)
		(size 0.4572)
		(drill 0.2032)
		(layers "F.Cu" "B.Cu")
		(net "GND")
	)
	(via
		(at 300.238414 -195.616576)
		(size 0.4572)
		(drill 0.2032)
		(layers "F.Cu" "B.Cu")
		(net "GND")
	)
	(via
		(at 432.379882 -194.766692)
		(size 0.4572)
		(drill 0.2032)
		(layers "F.Cu" "B.Cu")
		(net "GND")
	)
	(via
		(at 334.25003 -427.699678)
		(size 0.4572)
		(drill 0.2032)
		(layers "F.Cu" "B.Cu")
		(net "GND")
	)
	(via
		(at 147.526502 -404.51786)
		(size 0.4572)
		(drill 0.254)
		(layers "F.Cu" "B.Cu")
		(net "GND")
	)
	(via
		(at 438.033414 -268.71676)
		(size 0.4572)
		(drill 0.2032)
		(layers "F.Cu" "B.Cu")
		(net "GND")
	)
	(via
		(at 67.250056 -435.0512)
		(size 0.4572)
		(drill 0.2032)
		(layers "F.Cu" "B.Cu")
		(net "GND")
	)
	(via
		(at 268.829282 -305.266598)
		(size 0.4572)
		(drill 0.2032)
		(layers "F.Cu" "B.Cu")
		(net "GND")
	)
	(via
		(at 307.782214 -283.166566)
		(size 0.4572)
		(drill 0.2032)
		(layers "F.Cu" "B.Cu")
		(net "GND")
	)
	(via
		(at 207.071214 -228.766624)
		(size 0.4572)
		(drill 0.2032)
		(layers "F.Cu" "B.Cu")
		(net "GND")
	)
	(via
		(at 464.764882 -275.516594)
		(size 0.4572)
		(drill 0.2032)
		(layers "F.Cu" "B.Cu")
		(net "GND")
	)
	(via
		(at 339.954362 -270.19758)
		(size 0.4572)
		(drill 0.2032)
		(layers "F.Cu" "B.Cu")
		(net "GND")
	)
	(via
		(at 375.667016 -268.569694)
		(size 0.4572)
		(drill 0.2032)
		(layers "F.Cu" "B.Cu")
		(net "GND")
	)
	(via
		(at 375.667016 -278.336502)
		(size 0.4572)
		(drill 0.2032)
		(layers "F.Cu" "B.Cu")
		(net "GND")
	)
	(via
		(at 150.131526 -409.396184)
		(size 0.4572)
		(drill 0.254)
		(layers "F.Cu" "B.Cu")
		(net "GND")
	)
	(via
		(at 449.677282 -211.766658)
		(size 0.4572)
		(drill 0.2032)
		(layers "F.Cu" "B.Cu")
		(net "GND")
	)
	(via
		(at 438.033414 -223.666558)
		(size 0.4572)
		(drill 0.2032)
		(layers "F.Cu" "B.Cu")
		(net "GND")
	)
	(via
		(at 314.092082 -294.216582)
		(size 0.4572)
		(drill 0.2032)
		(layers "F.Cu" "B.Cu")
		(net "GND")
	)
	(via
		(at 182.637684 -319.294256)
		(size 0.4572)
		(drill 0.2032)
		(layers "F.Cu" "B.Cu")
		(net "GND")
	)
	(via
		(at 185.755788 -117.375432)
		(size 0.4572)
		(drill 0.254)
		(layers "F.Cu" "B.Cu")
		(net "GND")
	)
	(via
		(at 67.250056 -438.651396)
		(size 0.4572)
		(drill 0.2032)
		(layers "F.Cu" "B.Cu")
		(net "GND")
	)
	(via
		(at 164.052504 -75.242674)
		(size 0.508)
		(drill 0.254)
		(layers "F.Cu" "B.Cu")
		(net "GND")
	)
	(via
		(at 348.287848 -403.883876)
		(size 0.4064)
		(drill 0.2032)
		(layers "F.Cu" "B.Cu")
		(net "GND")
	)
	(via
		(at 207.071214 -301.01667)
		(size 0.4572)
		(drill 0.2032)
		(layers "F.Cu" "B.Cu")
		(net "GND")
	)
	(via
		(at 281.707082 -228.766624)
		(size 0.4572)
		(drill 0.2032)
		(layers "F.Cu" "B.Cu")
		(net "GND")
	)
	(via
		(at 361.012232 -334.282034)
		(size 0.49022)
		(drill 0.254)
		(layers "F.Cu" "B.Cu")
		(net "GND")
	)
	(via
		(at 31.876746 -217.716608)
		(size 0.4572)
		(drill 0.2032)
		(layers "F.Cu" "B.Cu")
		(net "GND")
	)
	(via
		(at 93.784166 -247.178322)
		(size 0.4572)
		(drill 0.2032)
		(layers "F.Cu" "B.Cu")
		(net "GND")
	)
	(via
		(at 374.14708 -236.597952)
		(size 0.4572)
		(drill 0.2032)
		(layers "F.Cu" "B.Cu")
		(net "GND")
	)
	(via
		(at 197.637146 -283.166566)
		(size 0.4572)
		(drill 0.2032)
		(layers "F.Cu" "B.Cu")
		(net "GND")
	)
	(via
		(at 434.589682 -196.466714)
		(size 0.4572)
		(drill 0.2032)
		(layers "F.Cu" "B.Cu")
		(net "GND")
	)
	(via
		(at 58.893456 -152.936702)
		(size 0.508)
		(drill 0.254)
		(layers "F.Cu" "B.Cu")
		(net "GND")
	)
	(via
		(at 122.68962 -297.19778)
		(size 0.508)
		(drill 0.254)
		(layers "F.Cu" "B.Cu")
		(net "GND")
	)
	(via
		(at 124.437394 -257.98907)
		(size 0.4572)
		(drill 0.2032)
		(layers "F.Cu" "B.Cu")
		(net "GND")
	)
	(via
		(at 384.955034 -247.178322)
		(size 0.4572)
		(drill 0.2032)
		(layers "F.Cu" "B.Cu")
		(net "GND")
	)
	(via
		(at 150.377906 -64.059308)
		(size 0.508)
		(drill 0.254)
		(layers "F.Cu" "B.Cu")
		(net "GND")
	)
	(via
		(at 136.349994 -432.451256)
		(size 0.4572)
		(drill 0.2032)
		(layers "F.Cu" "B.Cu")
		(net "GND")
	)
	(via
		(at 423.226484 -236.416596)
		(size 0.4572)
		(drill 0.2032)
		(layers "F.Cu" "B.Cu")
		(net "GND")
	)
	(via
		(at 372.438168 -160.435036)
		(size 0.508)
		(drill 0.254)
		(layers "F.Cu" "B.Cu")
		(net "GND")
	)
	(via
		(at 182.549546 -199.01662)
		(size 0.4572)
		(drill 0.2032)
		(layers "F.Cu" "B.Cu")
		(net "GND")
	)
	(via
		(at 376.606816 -255.547622)
		(size 0.4572)
		(drill 0.2032)
		(layers "F.Cu" "B.Cu")
		(net "GND")
	)
	(via
		(at 287.360614 -276.366732)
		(size 0.4572)
		(drill 0.2032)
		(layers "F.Cu" "B.Cu")
		(net "GND")
	)
	(via
		(at 214.615014 -239.81664)
		(size 0.4572)
		(drill 0.2032)
		(layers "F.Cu" "B.Cu")
		(net "GND")
	)
	(via
		(at 294.904414 -301.866808)
		(size 0.4572)
		(drill 0.2032)
		(layers "F.Cu" "B.Cu")
		(net "GND")
	)
	(via
		(at 176.896014 -213.46668)
		(size 0.4572)
		(drill 0.2032)
		(layers "F.Cu" "B.Cu")
		(net "GND")
	)
	(via
		(at 254.975614 -306.116736)
		(size 0.4572)
		(drill 0.2032)
		(layers "F.Cu" "B.Cu")
		(net "GND")
	)
	(via
		(at 13.345414 -284.866588)
		(size 0.4572)
		(drill 0.2032)
		(layers "F.Cu" "B.Cu")
		(net "GND")
	)
	(via
		(at 444.141352 -323.429376)
		(size 0.4572)
		(drill 0.2032)
		(layers "F.Cu" "B.Cu")
		(net "GND")
	)
	(via
		(at 432.379882 -305.266598)
		(size 0.4572)
		(drill 0.2032)
		(layers "F.Cu" "B.Cu")
		(net "GND")
	)
	(via
		(at 302.4378 -25.146)
		(size 0.508)
		(drill 0.254)
		(layers "F.Cu" "B.Cu")
		(net "GND")
	)
	(via
		(at 37.210746 -309.51678)
		(size 0.4572)
		(drill 0.2032)
		(layers "F.Cu" "B.Cu")
		(net "GND")
	)
	(via
		(at 285.150814 -281.466798)
		(size 0.4572)
		(drill 0.2032)
		(layers "F.Cu" "B.Cu")
		(net "GND")
	)
	(via
		(at 61.381386 -410.664152)
		(size 0.4572)
		(drill 0.254)
		(layers "F.Cu" "B.Cu")
		(net "GND")
	)
	(via
		(at 39.420546 -204.96657)
		(size 0.4572)
		(drill 0.2032)
		(layers "F.Cu" "B.Cu")
		(net "GND")
	)
	(via
		(at 86.735666 -241.481102)
		(size 0.4318)
		(drill 0.2032)
		(layers "F.Cu" "B.Cu")
		(net "GND")
	)
	(via
		(at 43.520614 -216.866724)
		(size 0.4572)
		(drill 0.2032)
		(layers "F.Cu" "B.Cu")
		(net "GND")
	)
	(via
		(at 439.923682 -305.266598)
		(size 0.4572)
		(drill 0.2032)
		(layers "F.Cu" "B.Cu")
		(net "GND")
	)
	(via
		(at 457.221082 -303.566576)
		(size 0.4572)
		(drill 0.2032)
		(layers "F.Cu" "B.Cu")
		(net "GND")
	)
	(via
		(at 183.39816 -412.48838)
		(size 0.508)
		(drill 0.254)
		(layers "F.Cu" "B.Cu")
		(net "GND")
	)
	(via
		(at 80.034638 -403.883876)
		(size 0.4064)
		(drill 0.2032)
		(layers "F.Cu" "B.Cu")
		(net "GND")
	)
	(via
		(at 57.404762 -159.56788)
		(size 0.508)
		(drill 0.254)
		(layers "F.Cu" "B.Cu")
		(net "GND")
	)
	(via
		(at 41.310814 -211.766658)
		(size 0.4572)
		(drill 0.2032)
		(layers "F.Cu" "B.Cu")
		(net "GND")
	)
	(via
		(at 172.795946 -195.616576)
		(size 0.4572)
		(drill 0.2032)
		(layers "F.Cu" "B.Cu")
		(net "GND")
	)
	(via
		(at 110.079282 -407.067766)
		(size 0.508)
		(drill 0.254)
		(layers "F.Cu" "B.Cu")
		(net "GND")
	)
	(via
		(at 184.439814 -280.61666)
		(size 0.4572)
		(drill 0.2032)
		(layers "F.Cu" "B.Cu")
		(net "GND")
	)
	(via
		(at 96.33585 -406.370536)
		(size 0.4572)
		(drill 0.254)
		(layers "F.Cu" "B.Cu")
		(net "GND")
	)
	(via
		(at 99.422966 -243.922804)
		(size 0.4572)
		(drill 0.2032)
		(layers "F.Cu" "B.Cu")
		(net "GND")
	)
	(via
		(at 361.569762 -284.847538)
		(size 0.4572)
		(drill 0.2032)
		(layers "F.Cu" "B.Cu")
		(net "GND")
	)
	(via
		(at 48.854614 -228.766624)
		(size 0.4572)
		(drill 0.2032)
		(layers "F.Cu" "B.Cu")
		(net "GND")
	)
	(via
		(at 31.751778 -97.554034)
		(size 0.508)
		(drill 0.254)
		(layers "F.Cu" "B.Cu")
		(net "GND")
	)
	(via
		(at 430.124616 -361.172506)
		(size 0.508)
		(drill 0.254)
		(layers "F.Cu" "B.Cu")
		(net "GND")
	)
	(via
		(at 434.4797 -175.597058)
		(size 0.508)
		(drill 0.254)
		(layers "F.Cu" "B.Cu")
		(net "GND")
	)
	(via
		(at 347.101668 -333.356458)
		(size 0.49022)
		(drill 0.254)
		(layers "F.Cu" "B.Cu")
		(net "GND")
	)
	(via
		(at 228.615494 -129.784348)
		(size 0.508)
		(drill 0.254)
		(layers "F.Cu" "B.Cu")
		(net "GND")
	)
	(via
		(at 337.478116 -403.249892)
		(size 0.4572)
		(drill 0.254)
		(layers "F.Cu" "B.Cu")
		(net "GND")
	)
	(via
		(at 132.785866 -233.34218)
		(size 0.4572)
		(drill 0.2032)
		(layers "F.Cu" "B.Cu")
		(net "GND")
	)
	(via
		(at 254.975614 -300.166786)
		(size 0.4572)
		(drill 0.2032)
		(layers "F.Cu" "B.Cu")
		(net "GND")
	)
	(via
		(at 37.210746 -285.716726)
		(size 0.4572)
		(drill 0.2032)
		(layers "F.Cu" "B.Cu")
		(net "GND")
	)
	(via
		(at 32.350964 -391.635996)
		(size 0.508)
		(drill 0.254)
		(layers "F.Cu" "B.Cu")
		(net "GND")
	)
	(via
		(at 361.652566 -366.465104)
		(size 0.508)
		(drill 0.254)
		(layers "F.Cu" "B.Cu")
		(net "GND")
	)
	(via
		(at 51.064414 -228.766624)
		(size 0.4572)
		(drill 0.2032)
		(layers "F.Cu" "B.Cu")
		(net "GND")
	)
	(via
		(at 122.917966 -235.783882)
		(size 0.4572)
		(drill 0.2032)
		(layers "F.Cu" "B.Cu")
		(net "GND")
	)
	(via
		(at 7.035546 -283.166566)
		(size 0.4572)
		(drill 0.2032)
		(layers "F.Cu" "B.Cu")
		(net "GND")
	)
	(via
		(at 329.437746 -53.149246)
		(size 0.4572)
		(drill 0.2032)
		(layers "F.Cu" "B.Cu")
		(net "GND")
	)
	(via
		(at 289.250882 -305.266598)
		(size 0.4572)
		(drill 0.2032)
		(layers "F.Cu" "B.Cu")
		(net "GND")
	)
	(via
		(at 281.707082 -266.1666)
		(size 0.4572)
		(drill 0.2032)
		(layers "F.Cu" "B.Cu")
		(net "GND")
	)
	(via
		(at 419.502082 -284.866588)
		(size 0.4572)
		(drill 0.2032)
		(layers "F.Cu" "B.Cu")
		(net "GND")
	)
	(via
		(at 14.579346 -261.916672)
		(size 0.4572)
		(drill 0.2032)
		(layers "F.Cu" "B.Cu")
		(net "GND")
	)
	(via
		(at 333.95666 -407.638504)
		(size 0.4572)
		(drill 0.254)
		(layers "F.Cu" "B.Cu")
		(net "GND")
	)
	(via
		(at 26.223214 -198.166736)
		(size 0.4572)
		(drill 0.2032)
		(layers "F.Cu" "B.Cu")
		(net "GND")
	)
	(via
		(at 99.377246 -355.866192)
		(size 0.508)
		(drill 0.254)
		(layers "F.Cu" "B.Cu")
		(net "GND")
	)
	(via
		(at 120.208294 -288.103056)
		(size 0.4572)
		(drill 0.2032)
		(layers "F.Cu" "B.Cu")
		(net "GND")
	)
	(via
		(at 102.352094 -286.475424)
		(size 0.4572)
		(drill 0.2032)
		(layers "F.Cu" "B.Cu")
		(net "GND")
	)
	(via
		(at 430.489614 -208.366614)
		(size 0.4572)
		(drill 0.2032)
		(layers "F.Cu" "B.Cu")
		(net "GND")
	)
	(via
		(at 64.35725 -401.492212)
		(size 0.4572)
		(drill 0.254)
		(layers "F.Cu" "B.Cu")
		(net "GND")
	)
	(via
		(at 73.28408 -39.893748)
		(size 0.508)
		(drill 0.254)
		(layers "F.Cu" "B.Cu")
		(net "GND")
	)
	(via
		(at 70.844918 -403.883876)
		(size 0.4064)
		(drill 0.2032)
		(layers "F.Cu" "B.Cu")
		(net "GND")
	)
	(via
		(at 429.05934 -360.090466)
		(size 0.508)
		(drill 0.254)
		(layers "F.Cu" "B.Cu")
		(net "GND")
	)
	(via
		(at 55.066946 -10.16508)
		(size 0.508)
		(drill 0.254)
		(layers "F.Cu" "B.Cu")
		(net "GND")
	)
	(via
		(at 28.638246 -397.406876)
		(size 0.508)
		(drill 0.254)
		(layers "F.Cu" "B.Cu")
		(net "GND")
	)
	(via
		(at 49.901094 -352.397822)
		(size 0.49022)
		(drill 0.254)
		(layers "F.Cu" "B.Cu")
		(net "GND")
	)
	(via
		(at 419.932866 -359.414572)
		(size 0.508)
		(drill 0.254)
		(layers "F.Cu" "B.Cu")
		(net "GND")
	)
	(via
		(at 62.051946 -283.166566)
		(size 0.4572)
		(drill 0.2032)
		(layers "F.Cu" "B.Cu")
		(net "GND")
	)
	(via
		(at 348.882462 -287.28924)
		(size 0.4572)
		(drill 0.2032)
		(layers "F.Cu" "B.Cu")
		(net "GND")
	)
	(via
		(at 450.911214 -246.616728)
		(size 0.4572)
		(drill 0.2032)
		(layers "F.Cu" "B.Cu")
		(net "GND")
	)
	(via
		(at 24.081994 -129.583942)
		(size 0.508)
		(drill 0.254)
		(layers "F.Cu" "B.Cu")
		(net "GND")
	)
	(via
		(at 365.354108 -239.306354)
		(size 0.4572)
		(drill 0.2032)
		(layers "F.Cu" "B.Cu")
		(net "GND")
	)
	(via
		(at 380.72568 -246.364506)
		(size 0.4572)
		(drill 0.2032)
		(layers "F.Cu" "B.Cu")
		(net "GND")
	)
	(via
		(at 133.365494 -265.314176)
		(size 0.4572)
		(drill 0.2032)
		(layers "F.Cu" "B.Cu")
		(net "GND")
	)
	(via
		(at 28.433014 -269.566644)
		(size 0.4572)
		(drill 0.2032)
		(layers "F.Cu" "B.Cu")
		(net "GND")
	)
	(via
		(at 125.267466 -230.086662)
		(size 0.4572)
		(drill 0.2032)
		(layers "F.Cu" "B.Cu")
		(net "GND")
	)
	(via
		(at 279.816814 -261.916672)
		(size 0.4572)
		(drill 0.2032)
		(layers "F.Cu" "B.Cu")
		(net "GND")
	)
	(via
		(at 16.789146 -285.716726)
		(size 0.4572)
		(drill 0.2032)
		(layers "F.Cu" "B.Cu")
		(net "GND")
	)
	(via
		(at 384.125216 -271.825212)
		(size 0.4572)
		(drill 0.2032)
		(layers "F.Cu" "B.Cu")
		(net "GND")
	)
	(via
		(at 51.882294 -351.608644)
		(size 0.49022)
		(drill 0.254)
		(layers "F.Cu" "B.Cu")
		(net "GND")
	)
	(via
		(at 2.764536 -188.390022)
		(size 0.508)
		(drill 0.254)
		(layers "F.Cu" "B.Cu")
		(net "GND")
	)
	(via
		(at 417.292282 -200.716642)
		(size 0.4572)
		(drill 0.2032)
		(layers "F.Cu" "B.Cu")
		(net "GND")
	)
	(via
		(at 104.121966 -216.25052)
		(size 0.4572)
		(drill 0.2032)
		(layers "F.Cu" "B.Cu")
		(net "GND")
	)
	(via
		(at 333.118714 -250.428506)
		(size 0.4572)
		(drill 0.2032)
		(layers "F.Cu" "B.Cu")
		(net "GND")
	)
	(via
		(at 377.43638 -229.272846)
		(size 0.4572)
		(drill 0.2032)
		(layers "F.Cu" "B.Cu")
		(net "GND")
	)
	(via
		(at 448.084448 -176.694592)
		(size 0.508)
		(drill 0.254)
		(layers "F.Cu" "B.Cu")
		(net "GND")
	)
	(via
		(at 90.604848 -282.405836)
		(size 0.4572)
		(drill 0.2032)
		(layers "F.Cu" "B.Cu")
		(net "GND")
	)
	(via
		(at 184.84088 -90.515948)
		(size 0.508)
		(drill 0.254)
		(layers "F.Cu" "B.Cu")
		(net "GND")
	)
	(via
		(at 337.845908 -14.99235)
		(size 0.508)
		(drill 0.254)
		(layers "F.Cu" "B.Cu")
		(net "GND")
	)
	(via
		(at 61.29401 -401.492212)
		(size 0.4572)
		(drill 0.254)
		(layers "F.Cu" "B.Cu")
		(net "GND")
	)
	(via
		(at 453.121014 -221.96679)
		(size 0.4572)
		(drill 0.2032)
		(layers "F.Cu" "B.Cu")
		(net "GND")
	)
	(via
		(at 376.703336 -339.114638)
		(size 0.49022)
		(drill 0.254)
		(layers "F.Cu" "B.Cu")
		(net "GND")
	)
	(via
		(at 406.179782 -403.249892)
		(size 0.4572)
		(drill 0.254)
		(layers "F.Cu" "B.Cu")
		(net "GND")
	)
	(via
		(at 409.349956 -431.29962)
		(size 0.4572)
		(drill 0.2032)
		(layers "F.Cu" "B.Cu")
		(net "GND")
	)
	(via
		(at 347.363034 -230.900478)
		(size 0.4572)
		(drill 0.2032)
		(layers "F.Cu" "B.Cu")
		(net "GND")
	)
	(via
		(at 84.385912 -222.761556)
		(size 0.4572)
		(drill 0.2032)
		(layers "F.Cu" "B.Cu")
		(net "GND")
	)
	(via
		(at 371.437662 -280.778204)
		(size 0.4572)
		(drill 0.2032)
		(layers "F.Cu" "B.Cu")
		(net "GND")
	)
	(via
		(at 287.360614 -214.316564)
		(size 0.4572)
		(drill 0.2032)
		(layers "F.Cu" "B.Cu")
		(net "GND")
	)
	(via
		(at 126.317248 -274.266914)
		(size 0.4572)
		(drill 0.2032)
		(layers "F.Cu" "B.Cu")
		(net "GND")
	)
	(via
		(at 233.742484 -46.771052)
		(size 0.508)
		(drill 0.254)
		(layers "F.Cu" "B.Cu")
		(net "GND")
	)
	(via
		(at 64.083438 -410.030168)
		(size 0.4064)
		(drill 0.2032)
		(layers "F.Cu" "B.Cu")
		(net "GND")
	)
	(via
		(at 51.064414 -316.316614)
		(size 0.4572)
		(drill 0.2032)
		(layers "F.Cu" "B.Cu")
		(net "GND")
	)
	(via
		(at 37.210746 -272.116804)
		(size 0.4572)
		(drill 0.2032)
		(layers "F.Cu" "B.Cu")
		(net "GND")
	)
	(via
		(at 340.250018 -431.451258)
		(size 0.4572)
		(drill 0.2032)
		(layers "F.Cu" "B.Cu")
		(net "GND")
	)
	(via
		(at 405.648414 -250.016772)
		(size 0.4572)
		(drill 0.2032)
		(layers "F.Cu" "B.Cu")
		(net "GND")
	)
	(via
		(at 29.666946 -273.816572)
		(size 0.4572)
		(drill 0.2032)
		(layers "F.Cu" "B.Cu")
		(net "GND")
	)
	(via
		(at 46.964346 -246.616728)
		(size 0.4572)
		(drill 0.2032)
		(layers "F.Cu" "B.Cu")
		(net "GND")
	)
	(via
		(at 157.708346 -208.366614)
		(size 0.4572)
		(drill 0.2032)
		(layers "F.Cu" "B.Cu")
		(net "GND")
	)
	(via
		(at 443.367414 -301.866808)
		(size 0.4572)
		(drill 0.2032)
		(layers "F.Cu" "B.Cu")
		(net "GND")
	)
	(via
		(at 18.679414 -280.61666)
		(size 0.4572)
		(drill 0.2032)
		(layers "F.Cu" "B.Cu")
		(net "GND")
	)
	(via
		(at 300.238414 -300.166786)
		(size 0.4572)
		(drill 0.2032)
		(layers "F.Cu" "B.Cu")
		(net "GND")
	)
	(via
		(at 104.88422 -15.893288)
		(size 0.508)
		(drill 0.254)
		(layers "F.Cu" "B.Cu")
		(net "GND")
	)
	(via
		(at 435.823614 -238.966756)
		(size 0.4572)
		(drill 0.2032)
		(layers "F.Cu" "B.Cu")
		(net "GND")
	)
	(via
		(at 173.978062 -26.661872)
		(size 0.508)
		(drill 0.254)
		(layers "F.Cu" "B.Cu")
		(net "GND")
	)
	(via
		(at 53.908706 -401.492212)
		(size 0.4572)
		(drill 0.254)
		(layers "F.Cu" "B.Cu")
		(net "GND")
	)
	(via
		(at 177.18913 -421.350948)
		(size 0.508)
		(drill 0.254)
		(layers "F.Cu" "B.Cu")
		(net "GND")
	)
	(via
		(at 415.402014 -246.616728)
		(size 0.4572)
		(drill 0.2032)
		(layers "F.Cu" "B.Cu")
		(net "GND")
	)
	(via
		(at 165.544754 -400.858228)
		(size 0.4064)
		(drill 0.2032)
		(layers "F.Cu" "B.Cu")
		(net "GND")
	)
	(via
		(at 460.664814 -281.466798)
		(size 0.4572)
		(drill 0.2032)
		(layers "F.Cu" "B.Cu")
		(net "GND")
	)
	(via
		(at 424.347386 -362.649262)
		(size 0.49022)
		(drill 0.254)
		(layers "F.Cu" "B.Cu")
		(net "GND")
	)
	(via
		(at 294.286686 -12.544552)
		(size 0.508)
		(drill 0.254)
		(layers "F.Cu" "B.Cu")
		(net "GND")
	)
	(via
		(at 186.649614 -284.866588)
		(size 0.4572)
		(drill 0.2032)
		(layers "F.Cu" "B.Cu")
		(net "GND")
	)
	(via
		(at 246.393716 -121.608342)
		(size 0.508)
		(drill 0.254)
		(layers "F.Cu" "B.Cu")
		(net "GND")
	)
	(via
		(at 306.548282 -297.616626)
		(size 0.4572)
		(drill 0.2032)
		(layers "F.Cu" "B.Cu")
		(net "GND")
	)
	(via
		(at 97.183448 -267.755878)
		(size 0.4572)
		(drill 0.2032)
		(layers "F.Cu" "B.Cu")
		(net "GND")
	)
	(via
		(at 350.126808 -59.95797)
		(size 0.508)
		(drill 0.254)
		(layers "F.Cu" "B.Cu")
		(net "GND")
	)
	(via
		(at 376.966734 -220.319854)
		(size 0.4572)
		(drill 0.2032)
		(layers "F.Cu" "B.Cu")
		(net "GND")
	)
	(via
		(at 281.707082 -297.616626)
		(size 0.4572)
		(drill 0.2032)
		(layers "F.Cu" "B.Cu")
		(net "GND")
	)
	(via
		(at 405.395938 -236.416596)
		(size 0.4572)
		(drill 0.2032)
		(layers "F.Cu" "B.Cu")
		(net "GND")
	)
	(via
		(at 169.352214 -282.316682)
		(size 0.4572)
		(drill 0.2032)
		(layers "F.Cu" "B.Cu")
		(net "GND")
	)
	(via
		(at 209.281014 -239.81664)
		(size 0.4572)
		(drill 0.2032)
		(layers "F.Cu" "B.Cu")
		(net "GND")
	)
	(via
		(at 262.519414 -261.916672)
		(size 0.4572)
		(drill 0.2032)
		(layers "F.Cu" "B.Cu")
		(net "GND")
	)
	(via
		(at 42.284904 -399.405856)
		(size 0.508)
		(drill 0.254)
		(layers "F.Cu" "B.Cu")
		(net "GND")
	)
	(via
		(at 426.505624 -18.491454)
		(size 0.508)
		(drill 0.254)
		(layers "F.Cu" "B.Cu")
		(net "GND")
	)
	(via
		(at 131.955794 -287.28924)
		(size 0.4572)
		(drill 0.2032)
		(layers "F.Cu" "B.Cu")
		(net "GND")
	)
	(via
		(at 165.252146 -208.366614)
		(size 0.4572)
		(drill 0.2032)
		(layers "F.Cu" "B.Cu")
		(net "GND")
	)
	(via
		(at 28.433014 -262.76681)
		(size 0.4572)
		(drill 0.2032)
		(layers "F.Cu" "B.Cu")
		(net "GND")
	)
	(via
		(at 411.958282 -222.816674)
		(size 0.4572)
		(drill 0.2032)
		(layers "F.Cu" "B.Cu")
		(net "GND")
	)
	(via
		(at 259.075682 -205.816708)
		(size 0.4572)
		(drill 0.2032)
		(layers "F.Cu" "B.Cu")
		(net "GND")
	)
	(via
		(at 351.654364 -262.12038)
		(size 0.4572)
		(drill 0.2032)
		(layers "F.Cu" "B.Cu")
		(net "GND")
	)
	(via
		(at 457.221082 -284.866588)
		(size 0.4572)
		(drill 0.2032)
		(layers "F.Cu" "B.Cu")
		(net "GND")
	)
	(via
		(at 306.548282 -247.466612)
		(size 0.4572)
		(drill 0.2032)
		(layers "F.Cu" "B.Cu")
		(net "GND")
	)
	(via
		(at 212.724746 -217.716608)
		(size 0.4572)
		(drill 0.2032)
		(layers "F.Cu" "B.Cu")
		(net "GND")
	)
	(via
		(at 291.460682 -299.316648)
		(size 0.4572)
		(drill 0.2032)
		(layers "F.Cu" "B.Cu")
		(net "GND")
	)
	(via
		(at 164.018214 -295.916604)
		(size 0.4572)
		(drill 0.2032)
		(layers "F.Cu" "B.Cu")
		(net "GND")
	)
	(via
		(at 91.434666 -213.732618)
		(size 0.4572)
		(drill 0.2032)
		(layers "F.Cu" "B.Cu")
		(net "GND")
	)
	(via
		(at 195.427346 -270.416782)
		(size 0.4572)
		(drill 0.2032)
		(layers "F.Cu" "B.Cu")
		(net "GND")
	)
	(via
		(at 268.829282 -291.666676)
		(size 0.4572)
		(drill 0.2032)
		(layers "F.Cu" "B.Cu")
		(net "GND")
	)
	(via
		(at 349.352362 -258.80314)
		(size 0.4572)
		(drill 0.2032)
		(layers "F.Cu" "B.Cu")
		(net "GND")
	)
	(via
		(at 165.252146 -231.316784)
		(size 0.4572)
		(drill 0.2032)
		(layers "F.Cu" "B.Cu")
		(net "GND")
	)
	(via
		(at 214.615014 -211.766658)
		(size 0.4572)
		(drill 0.2032)
		(layers "F.Cu" "B.Cu")
		(net "GND")
	)
	(via
		(at 300.022514 -210.916774)
		(size 0.4572)
		(drill 0.2032)
		(layers "F.Cu" "B.Cu")
		(net "GND")
	)
	(via
		(at 58.824114 -312.91657)
		(size 0.4572)
		(drill 0.2032)
		(layers "F.Cu" "B.Cu")
		(net "GND")
	)
	(via
		(at 317.020448 -410.030168)
		(size 0.4064)
		(drill 0.2032)
		(layers "F.Cu" "B.Cu")
		(net "GND")
	)
	(via
		(at 409.527248 -238.116618)
		(size 0.4572)
		(drill 0.2032)
		(layers "F.Cu" "B.Cu")
		(net "GND")
	)
	(via
		(at 371.907816 -255.547622)
		(size 0.4572)
		(drill 0.2032)
		(layers "F.Cu" "B.Cu")
		(net "GND")
	)
	(via
		(at 294.904414 -242.3668)
		(size 0.4572)
		(drill 0.2032)
		(layers "F.Cu" "B.Cu")
		(net "GND")
	)
	(via
		(at 177.9524 -95.367348)
		(size 0.508)
		(drill 0.254)
		(layers "F.Cu" "B.Cu")
		(net "GND")
	)
	(via
		(at 39.420546 -248.31675)
		(size 0.4572)
		(drill 0.2032)
		(layers "F.Cu" "B.Cu")
		(net "GND")
	)
	(via
		(at 176.896014 -233.86669)
		(size 0.4572)
		(drill 0.2032)
		(layers "F.Cu" "B.Cu")
		(net "GND")
	)
	(via
		(at 345.15171 -41.349422)
		(size 0.4572)
		(drill 0.2032)
		(layers "F.Cu" "B.Cu")
		(net "GND")
	)
	(via
		(at 139.628626 -244.458744)
		(size 0.4572)
		(drill 0.2032)
		(layers "F.Cu" "B.Cu")
		(net "GND")
	)
	(via
		(at 31.876746 -234.716574)
		(size 0.4572)
		(drill 0.2032)
		(layers "F.Cu" "B.Cu")
		(net "GND")
	)
	(via
		(at 184.439814 -269.566644)
		(size 0.4572)
		(drill 0.2032)
		(layers "F.Cu" "B.Cu")
		(net "GND")
	)
	(via
		(at 287.360614 -234.716574)
		(size 0.4572)
		(drill 0.2032)
		(layers "F.Cu" "B.Cu")
		(net "GND")
	)
	(via
		(at 421.54094 -100.260658)
		(size 0.508)
		(drill 0.254)
		(layers "F.Cu" "B.Cu")
		(net "GND")
	)
	(via
		(at 123.027694 -273.453098)
		(size 0.4572)
		(drill 0.2032)
		(layers "F.Cu" "B.Cu")
		(net "GND")
	)
	(via
		(at 97.92208 -109.032548)
		(size 0.508)
		(drill 0.254)
		(layers "F.Cu" "B.Cu")
		(net "GND")
	)
	(via
		(at 419.502082 -261.066788)
		(size 0.4572)
		(drill 0.2032)
		(layers "F.Cu" "B.Cu")
		(net "GND")
	)
	(via
		(at 209.281014 -244.066568)
		(size 0.4572)
		(drill 0.2032)
		(layers "F.Cu" "B.Cu")
		(net "GND")
	)
	(via
		(at 407.34996 -437.49976)
		(size 0.4572)
		(drill 0.2032)
		(layers "F.Cu" "B.Cu")
		(net "GND")
	)
	(via
		(at 175.005746 -242.3668)
		(size 0.4572)
		(drill 0.2032)
		(layers "F.Cu" "B.Cu")
		(net "GND")
	)
	(via
		(at 281.707082 -249.166634)
		(size 0.4572)
		(drill 0.2032)
		(layers "F.Cu" "B.Cu")
		(net "GND")
	)
	(via
		(at 460.844646 -68.487036)
		(size 0.508)
		(drill 0.254)
		(layers "F.Cu" "B.Cu")
		(net "GND")
	)
	(via
		(at 375.667016 -279.964134)
		(size 0.4572)
		(drill 0.2032)
		(layers "F.Cu" "B.Cu")
		(net "GND")
	)
	(via
		(at 54.508146 -278.066754)
		(size 0.4572)
		(drill 0.2032)
		(layers "F.Cu" "B.Cu")
		(net "GND")
	)
	(via
		(at 174.88408 -38.730428)
		(size 0.508)
		(drill 0.254)
		(layers "F.Cu" "B.Cu")
		(net "GND")
	)
	(via
		(at 254.975614 -315.46673)
		(size 0.4572)
		(drill 0.2032)
		(layers "F.Cu" "B.Cu")
		(net "GND")
	)
	(via
		(at 16.59509 -16.978376)
		(size 0.508)
		(drill 0.254)
		(layers "F.Cu" "B.Cu")
		(net "GND")
	)
	(via
		(at 279.816814 -285.716726)
		(size 0.4572)
		(drill 0.2032)
		(layers "F.Cu" "B.Cu")
		(net "GND")
	)
	(via
		(at 338.394548 -54.558946)
		(size 0.4572)
		(drill 0.2032)
		(layers "F.Cu" "B.Cu")
		(net "GND")
	)
	(via
		(at 126.350014 -431.451258)
		(size 0.4572)
		(drill 0.2032)
		(layers "F.Cu" "B.Cu")
		(net "GND")
	)
	(via
		(at 377.546616 -268.569694)
		(size 0.4572)
		(drill 0.2032)
		(layers "F.Cu" "B.Cu")
		(net "GND")
	)
	(via
		(at 28.433014 -230.466646)
		(size 0.4572)
		(drill 0.2032)
		(layers "F.Cu" "B.Cu")
		(net "GND")
	)
	(via
		(at 291.460682 -196.466714)
		(size 0.4572)
		(drill 0.2032)
		(layers "F.Cu" "B.Cu")
		(net "GND")
	)
	(via
		(at 415.630614 -208.366614)
		(size 0.4572)
		(drill 0.2032)
		(layers "F.Cu" "B.Cu")
		(net "GND")
	)
	(via
		(at 368.618262 -287.28924)
		(size 0.4572)
		(drill 0.2032)
		(layers "F.Cu" "B.Cu")
		(net "GND")
	)
	(via
		(at 409.485338 -310.366664)
		(size 0.4572)
		(drill 0.2032)
		(layers "F.Cu" "B.Cu")
		(net "GND")
	)
	(via
		(at 87.205566 -222.761556)
		(size 0.4572)
		(drill 0.2032)
		(layers "F.Cu" "B.Cu")
		(net "GND")
	)
	(via
		(at 430.489614 -217.716608)
		(size 0.4572)
		(drill 0.2032)
		(layers "F.Cu" "B.Cu")
		(net "GND")
	)
	(via
		(at 186.649614 -241.516662)
		(size 0.4572)
		(drill 0.2032)
		(layers "F.Cu" "B.Cu")
		(net "GND")
	)
	(via
		(at 130.906012 -246.364506)
		(size 0.4572)
		(drill 0.2032)
		(layers "F.Cu" "B.Cu")
		(net "GND")
	)
	(via
		(at 416.459924 -156.610304)
		(size 0.508)
		(drill 0.254)
		(layers "F.Cu" "B.Cu")
		(net "GND")
	)
	(via
		(at 309.992014 -281.466798)
		(size 0.4572)
		(drill 0.2032)
		(layers "F.Cu" "B.Cu")
		(net "GND")
	)
	(via
		(at 421.45204 -354.252022)
		(size 0.508)
		(drill 0.254)
		(layers "F.Cu" "B.Cu")
		(net "GND")
	)
	(via
		(at 108.42625 -240.588546)
		(size 0.4572)
		(drill 0.2032)
		(layers "F.Cu" "B.Cu")
		(net "GND")
	)
	(via
		(at 449.677282 -239.81664)
		(size 0.4572)
		(drill 0.2032)
		(layers "F.Cu" "B.Cu")
		(net "GND")
	)
	(via
		(at 307.782214 -225.36658)
		(size 0.4572)
		(drill 0.2032)
		(layers "F.Cu" "B.Cu")
		(net "GND")
	)
	(via
		(at 37.940234 -111.603282)
		(size 0.508)
		(drill 0.254)
		(layers "F.Cu" "B.Cu")
		(net "GND")
	)
	(via
		(at 415.402014 -217.716608)
		(size 0.4572)
		(drill 0.2032)
		(layers "F.Cu" "B.Cu")
		(net "GND")
	)
	(via
		(at 366.2172 -411.5562)
		(size 0.508)
		(drill 0.254)
		(layers "F.Cu" "B.Cu")
		(net "GND")
	)
	(via
		(at 24.332946 -217.716608)
		(size 0.4572)
		(drill 0.2032)
		(layers "F.Cu" "B.Cu")
		(net "GND")
	)
	(via
		(at 372.847616 -283.219906)
		(size 0.4572)
		(drill 0.2032)
		(layers "F.Cu" "B.Cu")
		(net "GND")
	)
	(via
		(at 328.53122 -21.354288)
		(size 0.508)
		(drill 0.254)
		(layers "F.Cu" "B.Cu")
		(net "GND")
	)
	(via
		(at 52.082446 -236.416596)
		(size 0.4572)
		(drill 0.2032)
		(layers "F.Cu" "B.Cu")
		(net "GND")
	)
	(via
		(at 300.022514 -217.716608)
		(size 0.4572)
		(drill 0.2032)
		(layers "F.Cu" "B.Cu")
		(net "GND")
	)
	(via
		(at 301.342044 -360.143298)
		(size 0.508)
		(drill 0.254)
		(layers "F.Cu" "B.Cu")
		(net "GND")
	)
	(via
		(at 291.460682 -284.866588)
		(size 0.4572)
		(drill 0.2032)
		(layers "F.Cu" "B.Cu")
		(net "GND")
	)
	(via
		(at 364.859316 -280.778204)
		(size 0.4572)
		(drill 0.2032)
		(layers "F.Cu" "B.Cu")
		(net "GND")
	)
	(via
		(at 447.467482 -215.166702)
		(size 0.4572)
		(drill 0.2032)
		(layers "F.Cu" "B.Cu")
		(net "GND")
	)
	(via
		(at 459.117446 -14.32941)
		(size 0.508)
		(drill 0.254)
		(layers "F.Cu" "B.Cu")
		(net "GND")
	)
	(via
		(at 464.764882 -228.766624)
		(size 0.4572)
		(drill 0.2032)
		(layers "F.Cu" "B.Cu")
		(net "GND")
	)
	(via
		(at 175.967136 -329.90663)
		(size 0.508)
		(drill 0.254)
		(layers "F.Cu" "B.Cu")
		(net "GND")
	)
	(via
		(at 163.63188 -118.836948)
		(size 0.508)
		(drill 0.254)
		(layers "F.Cu" "B.Cu")
		(net "GND")
	)
	(via
		(at 27.785822 -6.597396)
		(size 0.508)
		(drill 0.254)
		(layers "F.Cu" "B.Cu")
		(net "GND")
	)
	(via
		(at 138.894566 -224.389442)
		(size 0.4572)
		(drill 0.2032)
		(layers "F.Cu" "B.Cu")
		(net "GND")
	)
	(via
		(at 257.185414 -285.716726)
		(size 0.4572)
		(drill 0.2032)
		(layers "F.Cu" "B.Cu")
		(net "GND")
	)
	(via
		(at 413.192214 -242.3668)
		(size 0.4572)
		(drill 0.2032)
		(layers "F.Cu" "B.Cu")
		(net "GND")
	)
	(via
		(at 296.794682 -207.51673)
		(size 0.4572)
		(drill 0.2032)
		(layers "F.Cu" "B.Cu")
		(net "GND")
	)
	(via
		(at 350.762062 -287.28924)
		(size 0.4572)
		(drill 0.2032)
		(layers "F.Cu" "B.Cu")
		(net "GND")
	)
	(via
		(at 88.145366 -234.15625)
		(size 0.4572)
		(drill 0.2032)
		(layers "F.Cu" "B.Cu")
		(net "GND")
	)
	(via
		(at 59.385962 -168.86428)
		(size 0.508)
		(drill 0.254)
		(layers "F.Cu" "B.Cu")
		(net "GND")
	)
	(via
		(at 291.460682 -306.96662)
		(size 0.4572)
		(drill 0.2032)
		(layers "F.Cu" "B.Cu")
		(net "GND")
	)
	(via
		(at 322.161916 -404.51786)
		(size 0.4572)
		(drill 0.254)
		(layers "F.Cu" "B.Cu")
		(net "GND")
	)
	(via
		(at 161.808414 -200.716642)
		(size 0.4572)
		(drill 0.2032)
		(layers "F.Cu" "B.Cu")
		(net "GND")
	)
	(via
		(at 136.349994 -426.54728)
		(size 0.4572)
		(drill 0.2032)
		(layers "F.Cu" "B.Cu")
		(net "GND")
	)
	(via
		(at 438.033414 -203.266802)
		(size 0.4572)
		(drill 0.2032)
		(layers "F.Cu" "B.Cu")
		(net "GND")
	)
	(via
		(at 371.9068 -17.221708)
		(size 0.508)
		(drill 0.254)
		(layers "F.Cu" "B.Cu")
		(net "GND")
	)
	(via
		(at 321.7037 -410.664152)
		(size 0.4572)
		(drill 0.254)
		(layers "F.Cu" "B.Cu")
		(net "GND")
	)
	(via
		(at 97.653094 -271.825212)
		(size 0.4572)
		(drill 0.2032)
		(layers "F.Cu" "B.Cu")
		(net "GND")
	)
	(via
		(at 148.785326 -404.51786)
		(size 0.4572)
		(drill 0.254)
		(layers "F.Cu" "B.Cu")
		(net "GND")
	)
	(via
		(at 136.893554 -403.883876)
		(size 0.4064)
		(drill 0.2032)
		(layers "F.Cu" "B.Cu")
		(net "GND")
	)
	(via
		(at 357.810562 -278.336502)
		(size 0.4572)
		(drill 0.2032)
		(layers "F.Cu" "B.Cu")
		(net "GND")
	)
	(via
		(at 180.339746 -317.166752)
		(size 0.4572)
		(drill 0.2032)
		(layers "F.Cu" "B.Cu")
		(net "GND")
	)
	(via
		(at 407.858214 -225.36658)
		(size 0.4572)
		(drill 0.2032)
		(layers "F.Cu" "B.Cu")
		(net "GND")
	)
	(via
		(at 415.369502 -400.200368)
		(size 0.4572)
		(drill 0.254)
		(layers "F.Cu" "B.Cu")
		(net "GND")
	)
	(via
		(at 159.779462 -401.492212)
		(size 0.4572)
		(drill 0.254)
		(layers "F.Cu" "B.Cu")
		(net "GND")
	)
	(via
		(at 182.549546 -281.466798)
		(size 0.4572)
		(drill 0.2032)
		(layers "F.Cu" "B.Cu")
		(net "GND")
	)
	(via
		(at 336.74558 -335.187036)
		(size 0.49022)
		(drill 0.254)
		(layers "F.Cu" "B.Cu")
		(net "GND")
	)
	(via
		(at 167.461946 -204.96657)
		(size 0.4572)
		(drill 0.2032)
		(layers "F.Cu" "B.Cu")
		(net "GND")
	)
	(via
		(at 62.267846 -238.966756)
		(size 0.4572)
		(drill 0.2032)
		(layers "F.Cu" "B.Cu")
		(net "GND")
	)
	(via
		(at 414.756854 -9.424924)
		(size 0.508)
		(drill 0.254)
		(layers "F.Cu" "B.Cu")
		(net "GND")
	)
	(via
		(at 334.315562 -278.336502)
		(size 0.4318)
		(drill 0.2032)
		(layers "F.Cu" "B.Cu")
		(net "GND")
	)
	(via
		(at 58.608214 -289.966654)
		(size 0.4572)
		(drill 0.2032)
		(layers "F.Cu" "B.Cu")
		(net "GND")
	)
	(via
		(at 187.883546 -251.716794)
		(size 0.4572)
		(drill 0.2032)
		(layers "F.Cu" "B.Cu")
		(net "GND")
	)
	(via
		(at 438.033414 -287.416748)
		(size 0.4572)
		(drill 0.2032)
		(layers "F.Cu" "B.Cu")
		(net "GND")
	)
	(via
		(at 28.433014 -295.916604)
		(size 0.4572)
		(drill 0.2032)
		(layers "F.Cu" "B.Cu")
		(net "GND")
	)
	(via
		(at 24.332946 -270.416782)
		(size 0.4572)
		(drill 0.2032)
		(layers "F.Cu" "B.Cu")
		(net "GND")
	)
	(via
		(at 464.764882 -280.61666)
		(size 0.4572)
		(drill 0.2032)
		(layers "F.Cu" "B.Cu")
		(net "GND")
	)
	(via
		(at 126.677166 -222.761556)
		(size 0.4572)
		(drill 0.2032)
		(layers "F.Cu" "B.Cu")
		(net "GND")
	)
	(via
		(at 63.942214 -264.466578)
		(size 0.4572)
		(drill 0.2032)
		(layers "F.Cu" "B.Cu")
		(net "GND")
	)
	(via
		(at 219.10548 -127.803148)
		(size 0.508)
		(drill 0.254)
		(layers "F.Cu" "B.Cu")
		(net "GND")
	)
	(via
		(at 344.183462 -279.150318)
		(size 0.4572)
		(drill 0.2032)
		(layers "F.Cu" "B.Cu")
		(net "GND")
	)
	(via
		(at 352.104198 -69.9008)
		(size 0.508)
		(drill 0.254)
		(layers "F.Cu" "B.Cu")
		(net "GND")
	)
	(via
		(at 344.07348 -241.481102)
		(size 0.4572)
		(drill 0.2032)
		(layers "F.Cu" "B.Cu")
		(net "GND")
	)
	(via
		(at 125.00737 -331.08392)
		(size 0.508)
		(drill 0.254)
		(layers "F.Cu" "B.Cu")
		(net "GND")
	)
	(via
		(at 464.764882 -264.466578)
		(size 0.4572)
		(drill 0.2032)
		(layers "F.Cu" "B.Cu")
		(net "GND")
	)
	(via
		(at 119.744998 -328.68489)
		(size 0.6604)
		(drill 0.3302)
		(layers "F.Cu" "B.Cu")
		(net "GND")
	)
	(via
		(at 352.85172 -334.282034)
		(size 0.49022)
		(drill 0.254)
		(layers "F.Cu" "B.Cu")
		(net "GND")
	)
	(via
		(at 379.786134 -239.853216)
		(size 0.4572)
		(drill 0.2032)
		(layers "F.Cu" "B.Cu")
		(net "GND")
	)
	(via
		(at 446.677542 -22.125178)
		(size 0.508)
		(drill 0.254)
		(layers "F.Cu" "B.Cu")
		(net "GND")
	)
	(via
		(at 411.958282 -245.76659)
		(size 0.4572)
		(drill 0.2032)
		(layers "F.Cu" "B.Cu")
		(net "GND")
	)
	(via
		(at 146.083274 -403.883876)
		(size 0.4064)
		(drill 0.2032)
		(layers "F.Cu" "B.Cu")
		(net "GND")
	)
	(via
		(at 386.350002 -432.747166)
		(size 0.4572)
		(drill 0.2032)
		(layers "F.Cu" "B.Cu")
		(net "GND")
	)
	(via
		(at 225.11512 -44.21759)
		(size 0.508)
		(drill 0.254)
		(layers "F.Cu" "B.Cu")
		(net "GND")
	)
	(via
		(at 48.854614 -205.816708)
		(size 0.4572)
		(drill 0.2032)
		(layers "F.Cu" "B.Cu")
		(net "GND")
	)
	(via
		(at 63.250064 -433.899564)
		(size 0.4572)
		(drill 0.2032)
		(layers "F.Cu" "B.Cu")
		(net "GND")
	)
	(via
		(at 411.958282 -213.46668)
		(size 0.4572)
		(drill 0.2032)
		(layers "F.Cu" "B.Cu")
		(net "GND")
	)
	(via
		(at 54.508146 -285.716726)
		(size 0.4572)
		(drill 0.2032)
		(layers "F.Cu" "B.Cu")
		(net "GND")
	)
	(via
		(at 408.9781 -319.321688)
		(size 0.4572)
		(drill 0.2032)
		(layers "F.Cu" "B.Cu")
		(net "GND")
	)
	(via
		(at 329.25004 -437.34736)
		(size 0.4572)
		(drill 0.2032)
		(layers "F.Cu" "B.Cu")
		(net "GND")
	)
	(via
		(at 267.5128 -155.489148)
		(size 0.508)
		(drill 0.254)
		(layers "F.Cu" "B.Cu")
		(net "GND")
	)
	(via
		(at 59.842146 -258.516628)
		(size 0.4572)
		(drill 0.2032)
		(layers "F.Cu" "B.Cu")
		(net "GND")
	)
	(via
		(at 375.90857 -403.883876)
		(size 0.4064)
		(drill 0.2032)
		(layers "F.Cu" "B.Cu")
		(net "GND")
	)
	(via
		(at 409.748482 -289.966654)
		(size 0.4572)
		(drill 0.2032)
		(layers "F.Cu" "B.Cu")
		(net "GND")
	)
	(via
		(at 190.093346 -231.316784)
		(size 0.4572)
		(drill 0.2032)
		(layers "F.Cu" "B.Cu")
		(net "GND")
	)
	(via
		(at 25.746964 -7.215124)
		(size 0.508)
		(drill 0.254)
		(layers "F.Cu" "B.Cu")
		(net "GND")
	)
	(via
		(at 366.159034 -226.017328)
		(size 0.4572)
		(drill 0.2032)
		(layers "F.Cu" "B.Cu")
		(net "GND")
	)
	(via
		(at 432.093624 -19.759422)
		(size 0.508)
		(drill 0.254)
		(layers "F.Cu" "B.Cu")
		(net "GND")
	)
	(via
		(at 184.023 -425.831)
		(size 0.508)
		(drill 0.254)
		(layers "F.Cu" "B.Cu")
		(net "GND")
	)
	(via
		(at 302.6918 -14.432788)
		(size 0.508)
		(drill 0.254)
		(layers "F.Cu" "B.Cu")
		(net "GND")
	)
	(via
		(at 214.615014 -280.61666)
		(size 0.4572)
		(drill 0.2032)
		(layers "F.Cu" "B.Cu")
		(net "GND")
	)
	(via
		(at 467.535514 -93.84538)
		(size 0.508)
		(drill 0.254)
		(layers "F.Cu" "B.Cu")
		(net "GND")
	)
	(via
		(at 161.54273 -312.892948)
		(size 0.4572)
		(drill 0.2032)
		(layers "F.Cu" "B.Cu")
		(net "GND")
	)
	(via
		(at 24.332946 -227.066602)
		(size 0.4572)
		(drill 0.2032)
		(layers "F.Cu" "B.Cu")
		(net "GND")
	)
	(via
		(at 56.912256 -161.572702)
		(size 0.508)
		(drill 0.254)
		(layers "F.Cu" "B.Cu")
		(net "GND")
	)
	(via
		(at 151.349964 -438.651396)
		(size 0.4572)
		(drill 0.2032)
		(layers "F.Cu" "B.Cu")
		(net "GND")
	)
	(via
		(at 337.478116 -401.492212)
		(size 0.4572)
		(drill 0.254)
		(layers "F.Cu" "B.Cu")
		(net "GND")
	)
	(via
		(at 333.73568 -217.064336)
		(size 0.4572)
		(drill 0.2032)
		(layers "F.Cu" "B.Cu")
		(net "GND")
	)
	(via
		(at 413.192214 -283.166566)
		(size 0.4572)
		(drill 0.2032)
		(layers "F.Cu" "B.Cu")
		(net "GND")
	)
	(via
		(at 420.736014 -296.766742)
		(size 0.4572)
		(drill 0.2032)
		(layers "F.Cu" "B.Cu")
		(net "GND")
	)
	(via
		(at 384.015234 -224.389442)
		(size 0.4572)
		(drill 0.2032)
		(layers "F.Cu" "B.Cu")
		(net "GND")
	)
	(via
		(at 172.795946 -290.816792)
		(size 0.4572)
		(drill 0.2032)
		(layers "F.Cu" "B.Cu")
		(net "GND")
	)
	(via
		(at 118.798848 -277.522432)
		(size 0.4572)
		(drill 0.2032)
		(layers "F.Cu" "B.Cu")
		(net "GND")
	)
	(via
		(at 302.448214 -212.616796)
		(size 0.4572)
		(drill 0.2032)
		(layers "F.Cu" "B.Cu")
		(net "GND")
	)
	(via
		(at 300.238414 -317.166752)
		(size 0.4572)
		(drill 0.2032)
		(layers "F.Cu" "B.Cu")
		(net "GND")
	)
	(via
		(at 121.617994 -279.150318)
		(size 0.4572)
		(drill 0.2032)
		(layers "F.Cu" "B.Cu")
		(net "GND")
	)
	(via
		(at 356.291134 -220.319854)
		(size 0.4572)
		(drill 0.2032)
		(layers "F.Cu" "B.Cu")
		(net "GND")
	)
	(via
		(at 101.617018 -330.382626)
		(size 0.508)
		(drill 0.254)
		(layers "F.Cu" "B.Cu")
		(net "GND")
	)
	(via
		(at 90.134694 -283.219906)
		(size 0.4572)
		(drill 0.2032)
		(layers "F.Cu" "B.Cu")
		(net "GND")
	)
	(via
		(at 384.015234 -243.922804)
		(size 0.4572)
		(drill 0.2032)
		(layers "F.Cu" "B.Cu")
		(net "GND")
	)
	(via
		(at 9.245346 -313.766708)
		(size 0.4572)
		(drill 0.2032)
		(layers "F.Cu" "B.Cu")
		(net "GND")
	)
	(via
		(at 161.808414 -241.516662)
		(size 0.4572)
		(drill 0.2032)
		(layers "F.Cu" "B.Cu")
		(net "GND")
	)
	(via
		(at 415.73069 -403.883876)
		(size 0.4064)
		(drill 0.2032)
		(layers "F.Cu" "B.Cu")
		(net "GND")
	)
	(via
		(at 262.266938 -65.005712)
		(size 0.6604)
		(drill 0.3302)
		(layers "F.Cu" "B.Cu")
		(net "GND")
	)
	(via
		(at 309.992014 -289.11677)
		(size 0.4572)
		(drill 0.2032)
		(layers "F.Cu" "B.Cu")
		(net "GND")
	)
	(via
		(at 425.591986 -362.649262)
		(size 0.49022)
		(drill 0.254)
		(layers "F.Cu" "B.Cu")
		(net "GND")
	)
	(via
		(at 31.876746 -270.416782)
		(size 0.4572)
		(drill 0.2032)
		(layers "F.Cu" "B.Cu")
		(net "GND")
	)
	(via
		(at 87.31504 -275.08073)
		(size 0.4572)
		(drill 0.2032)
		(layers "F.Cu" "B.Cu")
		(net "GND")
	)
	(via
		(at 435.823614 -289.11677)
		(size 0.4572)
		(drill 0.2032)
		(layers "F.Cu" "B.Cu")
		(net "GND")
	)
	(via
		(at 304.122582 -272.966688)
		(size 0.4572)
		(drill 0.2032)
		(layers "F.Cu" "B.Cu")
		(net "GND")
	)
	(via
		(at 124.327412 -233.34218)
		(size 0.4572)
		(drill 0.2032)
		(layers "F.Cu" "B.Cu")
		(net "GND")
	)
	(via
		(at 356.291134 -213.732618)
		(size 0.4572)
		(drill 0.2032)
		(layers "F.Cu" "B.Cu")
		(net "GND")
	)
	(via
		(at 405.349964 -430.147222)
		(size 0.4572)
		(drill 0.2032)
		(layers "F.Cu" "B.Cu")
		(net "GND")
	)
	(via
		(at 366.269016 -283.219906)
		(size 0.4572)
		(drill 0.2032)
		(layers "F.Cu" "B.Cu")
		(net "GND")
	)
	(via
		(at 340.784434 -219.506038)
		(size 0.4572)
		(drill 0.2032)
		(layers "F.Cu" "B.Cu")
		(net "GND")
	)
	(via
		(at 386.00507 -255.547368)
		(size 0.4318)
		(drill 0.2032)
		(layers "F.Cu" "B.Cu")
		(net "GND")
	)
	(via
		(at 157.708346 -195.616576)
		(size 0.4572)
		(drill 0.2032)
		(layers "F.Cu" "B.Cu")
		(net "GND")
	)
	(via
		(at 427.045882 -272.966688)
		(size 0.4572)
		(drill 0.2032)
		(layers "F.Cu" "B.Cu")
		(net "GND")
	)
	(via
		(at 460.664814 -240.666778)
		(size 0.4572)
		(drill 0.2032)
		(layers "F.Cu" "B.Cu")
		(net "GND")
	)
	(via
		(at 277.607014 -214.316564)
		(size 0.4572)
		(drill 0.2032)
		(layers "F.Cu" "B.Cu")
		(net "GND")
	)
	(via
		(at 154.637994 -410.030168)
		(size 0.4064)
		(drill 0.2032)
		(layers "F.Cu" "B.Cu")
		(net "GND")
	)
	(via
		(at 412.015686 -174.363126)
		(size 0.508)
		(drill 0.254)
		(layers "F.Cu" "B.Cu")
		(net "GND")
	)
	(via
		(at 52.082446 -220.266768)
		(size 0.4572)
		(drill 0.2032)
		(layers "F.Cu" "B.Cu")
		(net "GND")
	)
	(via
		(at 35.976814 -216.866724)
		(size 0.4572)
		(drill 0.2032)
		(layers "F.Cu" "B.Cu")
		(net "GND")
	)
	(via
		(at 78.250034 -437.34736)
		(size 0.4572)
		(drill 0.2032)
		(layers "F.Cu" "B.Cu")
		(net "GND")
	)
	(via
		(at 445.577214 -199.01662)
		(size 0.4572)
		(drill 0.2032)
		(layers "F.Cu" "B.Cu")
		(net "GND")
	)
	(via
		(at 411.958282 -232.166668)
		(size 0.4572)
		(drill 0.2032)
		(layers "F.Cu" "B.Cu")
		(net "GND")
	)
	(via
		(at 363.953298 -297.197526)
		(size 0.508)
		(drill 0.254)
		(layers "F.Cu" "B.Cu")
		(net "GND")
	)
	(via
		(at 184.439814 -233.86669)
		(size 0.4572)
		(drill 0.2032)
		(layers "F.Cu" "B.Cu")
		(net "GND")
	)
	(via
		(at 12.094972 -104.930702)
		(size 0.508)
		(drill 0.254)
		(layers "F.Cu" "B.Cu")
		(net "GND")
	)
	(via
		(at 95.303594 -262.872474)
		(size 0.4572)
		(drill 0.2032)
		(layers "F.Cu" "B.Cu")
		(net "GND")
	)
	(via
		(at 455.011282 -196.466714)
		(size 0.4572)
		(drill 0.2032)
		(layers "F.Cu" "B.Cu")
		(net "GND")
	)
	(via
		(at 100.72878 -120.040908)
		(size 0.508)
		(drill 0.254)
		(layers "F.Cu" "B.Cu")
		(net "GND")
	)
	(via
		(at 165.252146 -201.56678)
		(size 0.4572)
		(drill 0.2032)
		(layers "F.Cu" "B.Cu")
		(net "GND")
	)
	(via
		(at 49.755552 -156.228034)
		(size 0.508)
		(drill 0.254)
		(layers "F.Cu" "B.Cu")
		(net "GND")
	)
	(via
		(at 180.339746 -240.666778)
		(size 0.4572)
		(drill 0.2032)
		(layers "F.Cu" "B.Cu")
		(net "GND")
	)
	(via
		(at 195.427346 -309.51678)
		(size 0.4572)
		(drill 0.2032)
		(layers "F.Cu" "B.Cu")
		(net "GND")
	)
	(via
		(at 438.033414 -309.51678)
		(size 0.4572)
		(drill 0.2032)
		(layers "F.Cu" "B.Cu")
		(net "GND")
	)
	(via
		(at 201.737214 -239.81664)
		(size 0.4572)
		(drill 0.2032)
		(layers "F.Cu" "B.Cu")
		(net "GND")
	)
	(via
		(at 294.904414 -251.716794)
		(size 0.4572)
		(drill 0.2032)
		(layers "F.Cu" "B.Cu")
		(net "GND")
	)
	(via
		(at 212.724746 -258.516628)
		(size 0.4572)
		(drill 0.2032)
		(layers "F.Cu" "B.Cu")
		(net "GND")
	)
	(via
		(at 374.727216 -270.19758)
		(size 0.4572)
		(drill 0.2032)
		(layers "F.Cu" "B.Cu")
		(net "GND")
	)
	(via
		(at 85.79993 -403.249892)
		(size 0.4572)
		(drill 0.254)
		(layers "F.Cu" "B.Cu")
		(net "GND")
	)
	(via
		(at 11.135614 -249.166634)
		(size 0.4572)
		(drill 0.2032)
		(layers "F.Cu" "B.Cu")
		(net "GND")
	)
	(via
		(at 13.94968 -44.99991)
		(size 0.508)
		(drill 0.254)
		(layers "F.Cu" "B.Cu")
		(net "GND")
	)
	(via
		(at 348.412816 -260.430772)
		(size 0.4572)
		(drill 0.2032)
		(layers "F.Cu" "B.Cu")
		(net "GND")
	)
	(via
		(at 270.063214 -309.51678)
		(size 0.4572)
		(drill 0.2032)
		(layers "F.Cu" "B.Cu")
		(net "GND")
	)
	(via
		(at 384.350006 -436.051198)
		(size 0.4572)
		(drill 0.2032)
		(layers "F.Cu" "B.Cu")
		(net "GND")
	)
	(via
		(at 142.502636 -338.91601)
		(size 0.508)
		(drill 0.254)
		(layers "F.Cu" "B.Cu")
		(net "GND")
	)
	(via
		(at 187.883546 -279.766776)
		(size 0.4572)
		(drill 0.2032)
		(layers "F.Cu" "B.Cu")
		(net "GND")
	)
	(via
		(at 66.152014 -258.516628)
		(size 0.4572)
		(drill 0.2032)
		(layers "F.Cu" "B.Cu")
		(net "GND")
	)
	(via
		(at 319.098676 -400.224244)
		(size 0.4572)
		(drill 0.254)
		(layers "F.Cu" "B.Cu")
		(net "GND")
	)
	(via
		(at 317.250064 -427.699678)
		(size 0.4572)
		(drill 0.2032)
		(layers "F.Cu" "B.Cu")
		(net "GND")
	)
	(via
		(at 377.153932 -77.712824)
		(size 0.508)
		(drill 0.254)
		(layers "F.Cu" "B.Cu")
		(net "GND")
	)
	(via
		(at 176.45888 -124.958348)
		(size 0.508)
		(drill 0.254)
		(layers "F.Cu" "B.Cu")
		(net "GND")
	)
	(via
		(at 316.035436 -403.249892)
		(size 0.4572)
		(drill 0.254)
		(layers "F.Cu" "B.Cu")
		(net "GND")
	)
	(via
		(at 157.708346 -279.766776)
		(size 0.4572)
		(drill 0.2032)
		(layers "F.Cu" "B.Cu")
		(net "GND")
	)
	(via
		(at 413.192214 -300.166786)
		(size 0.4572)
		(drill 0.2032)
		(layers "F.Cu" "B.Cu")
		(net "GND")
	)
	(via
		(at 361.460034 -222.761556)
		(size 0.4572)
		(drill 0.2032)
		(layers "F.Cu" "B.Cu")
		(net "GND")
	)
	(via
		(at 133.255766 -216.25052)
		(size 0.4572)
		(drill 0.2032)
		(layers "F.Cu" "B.Cu")
		(net "GND")
	)
	(via
		(at 328.943462 -35.605974)
		(size 0.508)
		(drill 0.254)
		(layers "F.Cu" "B.Cu")
		(net "GND")
	)
	(via
		(at 254.975614 -244.916706)
		(size 0.4572)
		(drill 0.2032)
		(layers "F.Cu" "B.Cu")
		(net "GND")
	)
	(via
		(at 405.648414 -296.766742)
		(size 0.4572)
		(drill 0.2032)
		(layers "F.Cu" "B.Cu")
		(net "GND")
	)
	(via
		(at 97.183194 -284.033722)
		(size 0.4572)
		(drill 0.2032)
		(layers "F.Cu" "B.Cu")
		(net "GND")
	)
	(via
		(at 268.829282 -271.266666)
		(size 0.4572)
		(drill 0.2032)
		(layers "F.Cu" "B.Cu")
		(net "GND")
	)
	(via
		(at 50.145442 -161.415984)
		(size 0.508)
		(drill 0.254)
		(layers "F.Cu" "B.Cu")
		(net "GND")
	)
	(via
		(at 442.133482 -230.466646)
		(size 0.4572)
		(drill 0.2032)
		(layers "F.Cu" "B.Cu")
		(net "GND")
	)
	(via
		(at 35.976814 -299.316648)
		(size 0.4572)
		(drill 0.2032)
		(layers "F.Cu" "B.Cu")
		(net "GND")
	)
	(via
		(at 48.854614 -258.516628)
		(size 0.4572)
		(drill 0.2032)
		(layers "F.Cu" "B.Cu")
		(net "GND")
	)
	(via
		(at 419.502082 -204.116686)
		(size 0.4572)
		(drill 0.2032)
		(layers "F.Cu" "B.Cu")
		(net "GND")
	)
	(via
		(at 89.554812 -231.714548)
		(size 0.4572)
		(drill 0.2032)
		(layers "F.Cu" "B.Cu")
		(net "GND")
	)
	(via
		(at 76.61021 -401.492212)
		(size 0.4572)
		(drill 0.254)
		(layers "F.Cu" "B.Cu")
		(net "GND")
	)
	(via
		(at 105.45699 -250.33732)
		(size 0.4572)
		(drill 0.2032)
		(layers "F.Cu" "B.Cu")
		(net "GND")
	)
	(via
		(at 43.520614 -196.466714)
		(size 0.4572)
		(drill 0.2032)
		(layers "F.Cu" "B.Cu")
		(net "GND")
	)
	(via
		(at 110.305088 -292.95598)
		(size 0.508)
		(drill 0.254)
		(layers "F.Cu" "B.Cu")
		(net "GND")
	)
	(via
		(at 279.816814 -203.266802)
		(size 0.4572)
		(drill 0.2032)
		(layers "F.Cu" "B.Cu")
		(net "GND")
	)
	(via
		(at 85.795612 -217.064336)
		(size 0.4572)
		(drill 0.2032)
		(layers "F.Cu" "B.Cu")
		(net "GND")
	)
	(via
		(at 431.428398 -194.56781)
		(size 0.508)
		(drill 0.254)
		(layers "F.Cu" "B.Cu")
		(net "GND")
	)
	(via
		(at 414.85947 -172.174154)
		(size 0.49022)
		(drill 0.254)
		(layers "F.Cu" "B.Cu")
		(net "GND")
	)
	(via
		(at 120.60301 -334.282034)
		(size 0.49022)
		(drill 0.254)
		(layers "F.Cu" "B.Cu")
		(net "GND")
	)
	(via
		(at 33.767014 -277.216616)
		(size 0.4572)
		(drill 0.2032)
		(layers "F.Cu" "B.Cu")
		(net "GND")
	)
	(via
		(at 195.427346 -317.166752)
		(size 0.4572)
		(drill 0.2032)
		(layers "F.Cu" "B.Cu")
		(net "GND")
	)
	(via
		(at 407.858214 -195.616576)
		(size 0.4572)
		(drill 0.2032)
		(layers "F.Cu" "B.Cu")
		(net "GND")
	)
	(via
		(at 388.366508 -8.20166)
		(size 0.508)
		(drill 0.254)
		(layers "F.Cu" "B.Cu")
		(net "GND")
	)
	(via
		(at 450.911214 -317.166752)
		(size 0.4572)
		(drill 0.2032)
		(layers "F.Cu" "B.Cu")
		(net "GND")
	)
	(via
		(at 291.460682 -294.216582)
		(size 0.4572)
		(drill 0.2032)
		(layers "F.Cu" "B.Cu")
		(net "GND")
	)
	(via
		(at 51.064414 -266.1666)
		(size 0.4572)
		(drill 0.2032)
		(layers "F.Cu" "B.Cu")
		(net "GND")
	)
	(via
		(at 300.238414 -279.766776)
		(size 0.4572)
		(drill 0.2032)
		(layers "F.Cu" "B.Cu")
		(net "GND")
	)
	(via
		(at 354.41128 -231.714548)
		(size 0.4572)
		(drill 0.2032)
		(layers "F.Cu" "B.Cu")
		(net "GND")
	)
	(via
		(at 457.221082 -266.1666)
		(size 0.4572)
		(drill 0.2032)
		(layers "F.Cu" "B.Cu")
		(net "GND")
	)
	(via
		(at 28.433014 -286.56661)
		(size 0.4572)
		(drill 0.2032)
		(layers "F.Cu" "B.Cu")
		(net "GND")
	)
	(via
		(at 354.591874 -172.892212)
		(size 0.508)
		(drill 0.254)
		(layers "F.Cu" "B.Cu")
		(net "GND")
	)
	(via
		(at 254.975614 -281.466798)
		(size 0.4572)
		(drill 0.2032)
		(layers "F.Cu" "B.Cu")
		(net "GND")
	)
	(via
		(at 161.399474 -403.883876)
		(size 0.4064)
		(drill 0.2032)
		(layers "F.Cu" "B.Cu")
		(net "GND")
	)
	(via
		(at 439.923682 -289.966654)
		(size 0.4572)
		(drill 0.2032)
		(layers "F.Cu" "B.Cu")
		(net "GND")
	)
	(via
		(at 347.473016 -258.80314)
		(size 0.4572)
		(drill 0.2032)
		(layers "F.Cu" "B.Cu")
		(net "GND")
	)
	(via
		(at 293.093902 -360.173524)
		(size 0.508)
		(drill 0.254)
		(layers "F.Cu" "B.Cu")
		(net "GND")
	)
	(via
		(at 416.328606 -6.586474)
		(size 0.508)
		(drill 0.254)
		(layers "F.Cu" "B.Cu")
		(net "GND")
	)
	(via
		(at 294.904414 -267.016738)
		(size 0.4572)
		(drill 0.2032)
		(layers "F.Cu" "B.Cu")
		(net "GND")
	)
	(via
		(at 307.782214 -261.916672)
		(size 0.4572)
		(drill 0.2032)
		(layers "F.Cu" "B.Cu")
		(net "GND")
	)
	(via
		(at 52.298346 -289.11677)
		(size 0.4572)
		(drill 0.2032)
		(layers "F.Cu" "B.Cu")
		(net "GND")
	)
	(via
		(at 180.339746 -217.716608)
		(size 0.4572)
		(drill 0.2032)
		(layers "F.Cu" "B.Cu")
		(net "GND")
	)
	(via
		(at 344.07348 -244.73662)
		(size 0.4572)
		(drill 0.2032)
		(layers "F.Cu" "B.Cu")
		(net "GND")
	)
	(via
		(at 345.15171 -40.348916)
		(size 0.4572)
		(drill 0.2032)
		(layers "F.Cu" "B.Cu")
		(net "GND")
	)
	(via
		(at 184.439814 -221.116652)
		(size 0.4572)
		(drill 0.2032)
		(layers "F.Cu" "B.Cu")
		(net "GND")
	)
	(via
		(at 66.94932 -55.531258)
		(size 0.508)
		(drill 0.254)
		(layers "F.Cu" "B.Cu")
		(net "GND")
	)
	(via
		(at 145.809462 -406.370536)
		(size 0.4572)
		(drill 0.254)
		(layers "F.Cu" "B.Cu")
		(net "GND")
	)
	(via
		(at 29.666946 -208.366614)
		(size 0.4572)
		(drill 0.2032)
		(layers "F.Cu" "B.Cu")
		(net "GND")
	)
	(via
		(at 370.028216 -281.59202)
		(size 0.4572)
		(drill 0.2032)
		(layers "F.Cu" "B.Cu")
		(net "GND")
	)
	(via
		(at 445.577214 -201.56678)
		(size 0.4572)
		(drill 0.2032)
		(layers "F.Cu" "B.Cu")
		(net "GND")
	)
	(via
		(at 182.549546 -313.766708)
		(size 0.4572)
		(drill 0.2032)
		(layers "F.Cu" "B.Cu")
		(net "GND")
	)
	(via
		(at 116.399056 -64.734948)
		(size 0.508)
		(drill 0.254)
		(layers "F.Cu" "B.Cu")
		(net "GND")
	)
	(via
		(at 291.460682 -226.216718)
		(size 0.4572)
		(drill 0.2032)
		(layers "F.Cu" "B.Cu")
		(net "GND")
	)
	(via
		(at 365.044228 -331.264514)
		(size 0.508)
		(drill 0.254)
		(layers "F.Cu" "B.Cu")
		(net "GND")
	)
	(via
		(at 382.135634 -243.922804)
		(size 0.4572)
		(drill 0.2032)
		(layers "F.Cu" "B.Cu")
		(net "GND")
	)
	(via
		(at 37.984684 -323.434456)
		(size 0.4572)
		(drill 0.2032)
		(layers "F.Cu" "B.Cu")
		(net "GND")
	)
	(via
		(at 309.45074 -410.664152)
		(size 0.4572)
		(drill 0.254)
		(layers "F.Cu" "B.Cu")
		(net "GND")
	)
	(via
		(at 342.19388 -238.225584)
		(size 0.4572)
		(drill 0.2032)
		(layers "F.Cu" "B.Cu")
		(net "GND")
	)
	(via
		(at 88.145366 -240.667286)
		(size 0.4572)
		(drill 0.2032)
		(layers "F.Cu" "B.Cu")
		(net "GND")
	)
	(via
		(at 172.795946 -267.016738)
		(size 0.4572)
		(drill 0.2032)
		(layers "F.Cu" "B.Cu")
		(net "GND")
	)
	(via
		(at 63.942214 -266.1666)
		(size 0.4572)
		(drill 0.2032)
		(layers "F.Cu" "B.Cu")
		(net "GND")
	)
	(via
		(at 317.250064 -428.851314)
		(size 0.4572)
		(drill 0.2032)
		(layers "F.Cu" "B.Cu")
		(net "GND")
	)
	(via
		(at 129.026412 -247.992138)
		(size 0.4572)
		(drill 0.2032)
		(layers "F.Cu" "B.Cu")
		(net "GND")
	)
	(via
		(at 126.316994 -269.38351)
		(size 0.4572)
		(drill 0.2032)
		(layers "F.Cu" "B.Cu")
		(net "GND")
	)
	(via
		(at 378.079 -104.178608)
		(size 0.508)
		(drill 0.254)
		(layers "F.Cu" "B.Cu")
		(net "GND")
	)
	(via
		(at 24.332946 -221.96679)
		(size 0.4572)
		(drill 0.2032)
		(layers "F.Cu" "B.Cu")
		(net "GND")
	)
	(via
		(at 153.34996 -432.451256)
		(size 0.4572)
		(drill 0.2032)
		(layers "F.Cu" "B.Cu")
		(net "GND")
	)
	(via
		(at 114.760502 -331.776832)
		(size 0.49022)
		(drill 0.254)
		(layers "F.Cu" "B.Cu")
		(net "GND")
	)
	(via
		(at 190.01359 -70.851268)
		(size 0.508)
		(drill 0.254)
		(layers "F.Cu" "B.Cu")
		(net "GND")
	)
	(via
		(at 337.604862 -261.244842)
		(size 0.4572)
		(drill 0.2032)
		(layers "F.Cu" "B.Cu")
		(net "GND")
	)
	(via
		(at 270.063214 -285.716726)
		(size 0.4572)
		(drill 0.2032)
		(layers "F.Cu" "B.Cu")
		(net "GND")
	)
	(via
		(at 370.563394 -297.197526)
		(size 0.508)
		(drill 0.254)
		(layers "F.Cu" "B.Cu")
		(net "GND")
	)
	(via
		(at 302.448214 -270.416782)
		(size 0.4572)
		(drill 0.2032)
		(layers "F.Cu" "B.Cu")
		(net "GND")
	)
	(via
		(at 263.5631 -32.725868)
		(size 0.508)
		(drill 0.254)
		(layers "F.Cu" "B.Cu")
		(net "GND")
	)
	(via
		(at 127.256794 -287.28924)
		(size 0.4572)
		(drill 0.2032)
		(layers "F.Cu" "B.Cu")
		(net "GND")
	)
	(via
		(at 171.562014 -267.866622)
		(size 0.4572)
		(drill 0.2032)
		(layers "F.Cu" "B.Cu")
		(net "GND")
	)
	(via
		(at 339.410802 -82.413094)
		(size 0.508)
		(drill 0.254)
		(layers "F.Cu" "B.Cu")
		(net "GND")
	)
	(via
		(at 112.110012 -215.436704)
		(size 0.4572)
		(drill 0.2032)
		(layers "F.Cu" "B.Cu")
		(net "GND")
	)
	(via
		(at 186.649614 -215.166702)
		(size 0.4572)
		(drill 0.2032)
		(layers "F.Cu" "B.Cu")
		(net "GND")
	)
	(via
		(at 294.904414 -300.166786)
		(size 0.4572)
		(drill 0.2032)
		(layers "F.Cu" "B.Cu")
		(net "GND")
	)
	(via
		(at 334.25003 -431.29962)
		(size 0.4572)
		(drill 0.2032)
		(layers "F.Cu" "B.Cu")
		(net "GND")
	)
	(via
		(at 82.73669 -404.51786)
		(size 0.4572)
		(drill 0.254)
		(layers "F.Cu" "B.Cu")
		(net "GND")
	)
	(via
		(at 190.063882 -319.268856)
		(size 0.4572)
		(drill 0.2032)
		(layers "F.Cu" "B.Cu")
		(net "GND")
	)
	(via
		(at 368.916204 -237.42015)
		(size 0.4572)
		(drill 0.2032)
		(layers "F.Cu" "B.Cu")
		(net "GND")
	)
	(via
		(at 274.163282 -239.81664)
		(size 0.4572)
		(drill 0.2032)
		(layers "F.Cu" "B.Cu")
		(net "GND")
	)
	(via
		(at 122.68962 -295.03878)
		(size 0.508)
		(drill 0.254)
		(layers "F.Cu" "B.Cu")
		(net "GND")
	)
	(via
		(at 130.076448 -279.150318)
		(size 0.4572)
		(drill 0.2032)
		(layers "F.Cu" "B.Cu")
		(net "GND")
	)
	(via
		(at 207.071214 -306.96662)
		(size 0.4572)
		(drill 0.2032)
		(layers "F.Cu" "B.Cu")
		(net "GND")
	)
	(via
		(at 378.956062 -275.8948)
		(size 0.4572)
		(drill 0.2032)
		(layers "F.Cu" "B.Cu")
		(net "GND")
	)
	(via
		(at 46.964346 -295.06672)
		(size 0.4572)
		(drill 0.2032)
		(layers "F.Cu" "B.Cu")
		(net "GND")
	)
	(via
		(at 195.427346 -290.816792)
		(size 0.4572)
		(drill 0.2032)
		(layers "F.Cu" "B.Cu")
		(net "GND")
	)
	(via
		(at 102.712012 -230.086662)
		(size 0.4572)
		(drill 0.2032)
		(layers "F.Cu" "B.Cu")
		(net "GND")
	)
	(via
		(at 307.782214 -307.816758)
		(size 0.4572)
		(drill 0.2032)
		(layers "F.Cu" "B.Cu")
		(net "GND")
	)
	(via
		(at 210.514946 -227.066602)
		(size 0.4572)
		(drill 0.2032)
		(layers "F.Cu" "B.Cu")
		(net "GND")
	)
	(via
		(at 194.61353 -106.225848)
		(size 0.508)
		(drill 0.254)
		(layers "F.Cu" "B.Cu")
		(net "GND")
	)
	(via
		(at 378.846334 -217.064336)
		(size 0.4572)
		(drill 0.2032)
		(layers "F.Cu" "B.Cu")
		(net "GND")
	)
	(via
		(at 289.250882 -222.816674)
		(size 0.4572)
		(drill 0.2032)
		(layers "F.Cu" "B.Cu")
		(net "GND")
	)
	(via
		(at 414.070292 -171.513754)
		(size 0.49022)
		(drill 0.254)
		(layers "F.Cu" "B.Cu")
		(net "GND")
	)
	(via
		(at 266.619482 -230.466646)
		(size 0.4572)
		(drill 0.2032)
		(layers "F.Cu" "B.Cu")
		(net "GND")
	)
	(via
		(at 164.018214 -284.866588)
		(size 0.4572)
		(drill 0.2032)
		(layers "F.Cu" "B.Cu")
		(net "GND")
	)
	(via
		(at 375.718578 -95.081852)
		(size 0.508)
		(drill 0.254)
		(layers "F.Cu" "B.Cu")
		(net "GND")
	)
	(via
		(at 84.793836 -269.94866)
		(size 0.4572)
		(drill 0.2032)
		(layers "F.Cu" "B.Cu")
		(net "GND")
	)
	(via
		(at 182.549546 -298.466764)
		(size 0.4572)
		(drill 0.2032)
		(layers "F.Cu" "B.Cu")
		(net "GND")
	)
	(via
		(at 259.075682 -194.766692)
		(size 0.4572)
		(drill 0.2032)
		(layers "F.Cu" "B.Cu")
		(net "GND")
	)
	(via
		(at 417.98875 -152.52573)
		(size 0.508)
		(drill 0.254)
		(layers "F.Cu" "B.Cu")
		(net "GND")
	)
	(via
		(at 191.983614 -297.616626)
		(size 0.4572)
		(drill 0.2032)
		(layers "F.Cu" "B.Cu")
		(net "GND")
	)
	(via
		(at 122.557794 -274.266914)
		(size 0.4572)
		(drill 0.2032)
		(layers "F.Cu" "B.Cu")
		(net "GND")
	)
	(via
		(at 119.234458 -201.48677)
		(size 0.6604)
		(drill 0.3302)
		(layers "F.Cu" "B.Cu")
		(net "GND")
	)
	(via
		(at 184.439814 -202.416664)
		(size 0.4572)
		(drill 0.2032)
		(layers "F.Cu" "B.Cu")
		(net "GND")
	)
	(via
		(at 36.15309 -19.770344)
		(size 0.508)
		(drill 0.254)
		(layers "F.Cu" "B.Cu")
		(net "GND")
	)
	(via
		(at 296.794682 -238.116618)
		(size 0.4572)
		(drill 0.2032)
		(layers "F.Cu" "B.Cu")
		(net "GND")
	)
	(via
		(at 76.697586 -407.638504)
		(size 0.4572)
		(drill 0.254)
		(layers "F.Cu" "B.Cu")
		(net "GND")
	)
	(via
		(at 128.35001 -433.747164)
		(size 0.4572)
		(drill 0.2032)
		(layers "F.Cu" "B.Cu")
		(net "GND")
	)
	(via
		(at 340.017608 -138.07186)
		(size 0.508)
		(drill 0.254)
		(layers "F.Cu" "B.Cu")
		(net "GND")
	)
	(via
		(at 349.242634 -245.55069)
		(size 0.4572)
		(drill 0.2032)
		(layers "F.Cu" "B.Cu")
		(net "GND")
	)
	(via
		(at 48.854614 -308.666642)
		(size 0.4572)
		(drill 0.2032)
		(layers "F.Cu" "B.Cu")
		(net "GND")
	)
	(via
		(at 294.904414 -195.616576)
		(size 0.4572)
		(drill 0.2032)
		(layers "F.Cu" "B.Cu")
		(net "GND")
	)
	(via
		(at 263.806686 -12.544552)
		(size 0.508)
		(drill 0.254)
		(layers "F.Cu" "B.Cu")
		(net "GND")
	)
	(via
		(at 176.896014 -269.566644)
		(size 0.4572)
		(drill 0.2032)
		(layers "F.Cu" "B.Cu")
		(net "GND")
	)
	(via
		(at 344.061288 -334.282034)
		(size 0.49022)
		(drill 0.254)
		(layers "F.Cu" "B.Cu")
		(net "GND")
	)
	(via
		(at 48.854614 -221.116652)
		(size 0.4572)
		(drill 0.2032)
		(layers "F.Cu" "B.Cu")
		(net "GND")
	)
	(via
		(at 370.858034 -222.761556)
		(size 0.4572)
		(drill 0.2032)
		(layers "F.Cu" "B.Cu")
		(net "GND")
	)
	(via
		(at 48.854614 -238.116618)
		(size 0.4572)
		(drill 0.2032)
		(layers "F.Cu" "B.Cu")
		(net "GND")
	)
	(via
		(at 397.198596 -17.601438)
		(size 0.508)
		(drill 0.254)
		(layers "F.Cu" "B.Cu")
		(net "GND")
	)
	(via
		(at 101.516942 -338.493862)
		(size 0.508)
		(drill 0.254)
		(layers "F.Cu" "B.Cu")
		(net "GND")
	)
	(via
		(at 205.180946 -263.616694)
		(size 0.4572)
		(drill 0.2032)
		(layers "F.Cu" "B.Cu")
		(net "GND")
	)
	(via
		(at 205.180946 -292.516814)
		(size 0.4572)
		(drill 0.2032)
		(layers "F.Cu" "B.Cu")
		(net "GND")
	)
	(via
		(at 458.455014 -261.916672)
		(size 0.4572)
		(drill 0.2032)
		(layers "F.Cu" "B.Cu")
		(net "GND")
	)
	(via
		(at 205.180946 -309.51678)
		(size 0.4572)
		(drill 0.2032)
		(layers "F.Cu" "B.Cu")
		(net "GND")
	)
	(via
		(at 342.250014 -430.147222)
		(size 0.4572)
		(drill 0.2032)
		(layers "F.Cu" "B.Cu")
		(net "GND")
	)
	(via
		(at 136.654794 -262.872474)
		(size 0.4572)
		(drill 0.2032)
		(layers "F.Cu" "B.Cu")
		(net "GND")
	)
	(via
		(at 125.267466 -213.732618)
		(size 0.4572)
		(drill 0.2032)
		(layers "F.Cu" "B.Cu")
		(net "GND")
	)
	(via
		(at 340.894416 -279.964134)
		(size 0.4572)
		(drill 0.2032)
		(layers "F.Cu" "B.Cu")
		(net "GND")
	)
	(via
		(at 107.520994 -271.011396)
		(size 0.4572)
		(drill 0.2032)
		(layers "F.Cu" "B.Cu")
		(net "GND")
	)
	(via
		(at 43.520614 -289.966654)
		(size 0.4572)
		(drill 0.2032)
		(layers "F.Cu" "B.Cu")
		(net "GND")
	)
	(via
		(at 184.439814 -306.96662)
		(size 0.4572)
		(drill 0.2032)
		(layers "F.Cu" "B.Cu")
		(net "GND")
	)
	(via
		(at 303.8094 -47.996348)
		(size 0.508)
		(drill 0.254)
		(layers "F.Cu" "B.Cu")
		(net "GND")
	)
	(via
		(at 327.83018 -407.638504)
		(size 0.4572)
		(drill 0.254)
		(layers "F.Cu" "B.Cu")
		(net "GND")
	)
	(via
		(at 257.185414 -279.766776)
		(size 0.4572)
		(drill 0.2032)
		(layers "F.Cu" "B.Cu")
		(net "GND")
	)
	(via
		(at 32.93618 -397.04264)
		(size 0.508)
		(drill 0.254)
		(layers "F.Cu" "B.Cu")
		(net "GND")
	)
	(via
		(at 130.906012 -231.714548)
		(size 0.4572)
		(drill 0.2032)
		(layers "F.Cu" "B.Cu")
		(net "GND")
	)
	(via
		(at 33.767014 -289.966654)
		(size 0.4572)
		(drill 0.2032)
		(layers "F.Cu" "B.Cu")
		(net "GND")
	)
	(via
		(at 304.122582 -210.066636)
		(size 0.4572)
		(drill 0.2032)
		(layers "F.Cu" "B.Cu")
		(net "GND")
	)
	(via
		(at 442.133482 -215.166702)
		(size 0.4572)
		(drill 0.2032)
		(layers "F.Cu" "B.Cu")
		(net "GND")
	)
	(via
		(at 374.726962 -283.219906)
		(size 0.4572)
		(drill 0.2032)
		(layers "F.Cu" "B.Cu")
		(net "GND")
	)
	(via
		(at 74.535538 -19.957542)
		(size 0.508)
		(drill 0.254)
		(layers "F.Cu" "B.Cu")
		(net "GND")
	)
	(via
		(at 16.789146 -311.216802)
		(size 0.4572)
		(drill 0.2032)
		(layers "F.Cu" "B.Cu")
		(net "GND")
	)
	(via
		(at 191.988186 -428.26686)
		(size 0.508)
		(drill 0.254)
		(layers "F.Cu" "B.Cu")
		(net "GND")
	)
	(via
		(at 399.349976 -431.451258)
		(size 0.4572)
		(drill 0.2032)
		(layers "F.Cu" "B.Cu")
		(net "GND")
	)
	(via
		(at 62.051946 -306.116736)
		(size 0.4572)
		(drill 0.2032)
		(layers "F.Cu" "B.Cu")
		(net "GND")
	)
	(via
		(at 11.135614 -277.216616)
		(size 0.4572)
		(drill 0.2032)
		(layers "F.Cu" "B.Cu")
		(net "GND")
	)
	(via
		(at 135.714994 -287.28924)
		(size 0.4572)
		(drill 0.2032)
		(layers "F.Cu" "B.Cu")
		(net "GND")
	)
	(via
		(at 438.033414 -276.366732)
		(size 0.4572)
		(drill 0.2032)
		(layers "F.Cu" "B.Cu")
		(net "GND")
	)
	(via
		(at 415.464752 -319.446656)
		(size 0.4572)
		(drill 0.2032)
		(layers "F.Cu" "B.Cu")
		(net "GND")
	)
	(via
		(at 83.770978 -246.02313)
		(size 0.6604)
		(drill 0.3302)
		(layers "F.Cu" "B.Cu")
		(net "GND")
	)
	(via
		(at 377.179332 -73.572624)
		(size 0.508)
		(drill 0.254)
		(layers "F.Cu" "B.Cu")
		(net "GND")
	)
	(via
		(at 197.637146 -292.516814)
		(size 0.4572)
		(drill 0.2032)
		(layers "F.Cu" "B.Cu")
		(net "GND")
	)
	(via
		(at 31.876746 -306.116736)
		(size 0.4572)
		(drill 0.2032)
		(layers "F.Cu" "B.Cu")
		(net "GND")
	)
	(via
		(at 262.519414 -220.266768)
		(size 0.4572)
		(drill 0.2032)
		(layers "F.Cu" "B.Cu")
		(net "GND")
	)
	(via
		(at 66.152014 -266.1666)
		(size 0.4572)
		(drill 0.2032)
		(layers "F.Cu" "B.Cu")
		(net "GND")
	)
	(via
		(at 98.592894 -260.430772)
		(size 0.4572)
		(drill 0.2032)
		(layers "F.Cu" "B.Cu")
		(net "GND")
	)
	(via
		(at 119.738394 -279.150318)
		(size 0.4572)
		(drill 0.2032)
		(layers "F.Cu" "B.Cu")
		(net "GND")
	)
	(via
		(at 51.064414 -210.066636)
		(size 0.4572)
		(drill 0.2032)
		(layers "F.Cu" "B.Cu")
		(net "GND")
	)
	(via
		(at 98.122994 -284.033722)
		(size 0.4572)
		(drill 0.2032)
		(layers "F.Cu" "B.Cu")
		(net "GND")
	)
	(via
		(at 125.377194 -279.150318)
		(size 0.4572)
		(drill 0.2032)
		(layers "F.Cu" "B.Cu")
		(net "GND")
	)
	(via
		(at 132.113274 -410.030168)
		(size 0.4064)
		(drill 0.2032)
		(layers "F.Cu" "B.Cu")
		(net "GND")
	)
	(via
		(at 336.08518 -216.25052)
		(size 0.4572)
		(drill 0.2032)
		(layers "F.Cu" "B.Cu")
		(net "GND")
	)
	(via
		(at 201.737214 -278.916638)
		(size 0.4572)
		(drill 0.2032)
		(layers "F.Cu" "B.Cu")
		(net "GND")
	)
	(via
		(at 387.77545 -35.589718)
		(size 0.508)
		(drill 0.254)
		(layers "F.Cu" "B.Cu")
		(net "GND")
	)
	(via
		(at 86.161118 -400.858228)
		(size 0.4064)
		(drill 0.2032)
		(layers "F.Cu" "B.Cu")
		(net "GND")
	)
	(via
		(at 59.626246 -287.416748)
		(size 0.4572)
		(drill 0.2032)
		(layers "F.Cu" "B.Cu")
		(net "GND")
	)
	(via
		(at 51.064414 -238.116618)
		(size 0.4572)
		(drill 0.2032)
		(layers "F.Cu" "B.Cu")
		(net "GND")
	)
	(via
		(at 45.528484 -323.434456)
		(size 0.4572)
		(drill 0.2032)
		(layers "F.Cu" "B.Cu")
		(net "GND")
	)
	(via
		(at 205.180946 -300.166786)
		(size 0.4572)
		(drill 0.2032)
		(layers "F.Cu" "B.Cu")
		(net "GND")
	)
	(via
		(at 314.092082 -232.166668)
		(size 0.4572)
		(drill 0.2032)
		(layers "F.Cu" "B.Cu")
		(net "GND")
	)
	(via
		(at 136.545066 -217.064336)
		(size 0.4572)
		(drill 0.2032)
		(layers "F.Cu" "B.Cu")
		(net "GND")
	)
	(via
		(at 31.876746 -313.766708)
		(size 0.4572)
		(drill 0.2032)
		(layers "F.Cu" "B.Cu")
		(net "GND")
	)
	(via
		(at 35.976814 -239.81664)
		(size 0.4572)
		(drill 0.2032)
		(layers "F.Cu" "B.Cu")
		(net "GND")
	)
	(via
		(at 430.489614 -250.016772)
		(size 0.4572)
		(drill 0.2032)
		(layers "F.Cu" "B.Cu")
		(net "GND")
	)
	(via
		(at 264.729214 -212.616796)
		(size 0.4572)
		(drill 0.2032)
		(layers "F.Cu" "B.Cu")
		(net "GND")
	)
	(via
		(at 93.27261 -409.396184)
		(size 0.4572)
		(drill 0.254)
		(layers "F.Cu" "B.Cu")
		(net "GND")
	)
	(via
		(at 122.562366 -409.396184)
		(size 0.4572)
		(drill 0.254)
		(layers "F.Cu" "B.Cu")
		(net "GND")
	)
	(via
		(at 382.135634 -247.178322)
		(size 0.4572)
		(drill 0.2032)
		(layers "F.Cu" "B.Cu")
		(net "GND")
	)
	(via
		(at 21.1074 -165.039548)
		(size 0.508)
		(drill 0.254)
		(layers "F.Cu" "B.Cu")
		(net "GND")
	)
	(via
		(at 309.992014 -317.166752)
		(size 0.4572)
		(drill 0.2032)
		(layers "F.Cu" "B.Cu")
		(net "GND")
	)
	(via
		(at 210.514946 -281.466798)
		(size 0.4572)
		(drill 0.2032)
		(layers "F.Cu" "B.Cu")
		(net "GND")
	)
	(via
		(at 435.823614 -231.316784)
		(size 0.4572)
		(drill 0.2032)
		(layers "F.Cu" "B.Cu")
		(net "GND")
	)
	(via
		(at 216.824814 -204.116686)
		(size 0.4572)
		(drill 0.2032)
		(layers "F.Cu" "B.Cu")
		(net "GND")
	)
	(via
		(at 84.495894 -260.430772)
		(size 0.4572)
		(drill 0.2032)
		(layers "F.Cu" "B.Cu")
		(net "GND")
	)
	(via
		(at 302.448214 -225.36658)
		(size 0.4572)
		(drill 0.2032)
		(layers "F.Cu" "B.Cu")
		(net "GND")
	)
	(via
		(at 342.664034 -230.900478)
		(size 0.4572)
		(drill 0.2032)
		(layers "F.Cu" "B.Cu")
		(net "GND")
	)
	(via
		(at 270.063214 -246.616728)
		(size 0.4572)
		(drill 0.2032)
		(layers "F.Cu" "B.Cu")
		(net "GND")
	)
	(via
		(at 162.384486 -409.396184)
		(size 0.4572)
		(drill 0.254)
		(layers "F.Cu" "B.Cu")
		(net "GND")
	)
	(via
		(at 334.324198 -43.751246)
		(size 0.4572)
		(drill 0.2032)
		(layers "F.Cu" "B.Cu")
		(net "GND")
	)
	(via
		(at 106.06405 -257.69316)
		(size 0.4572)
		(drill 0.2032)
		(layers "F.Cu" "B.Cu")
		(net "GND")
	)
	(via
		(at 274.163282 -301.01667)
		(size 0.4572)
		(drill 0.2032)
		(layers "F.Cu" "B.Cu")
		(net "GND")
	)
	(via
		(at 409.748482 -301.01667)
		(size 0.4572)
		(drill 0.2032)
		(layers "F.Cu" "B.Cu")
		(net "GND")
	)
	(via
		(at 132.425694 -276.708616)
		(size 0.4572)
		(drill 0.2032)
		(layers "F.Cu" "B.Cu")
		(net "GND")
	)
	(via
		(at 39.420546 -267.016738)
		(size 0.4572)
		(drill 0.2032)
		(layers "F.Cu" "B.Cu")
		(net "GND")
	)
	(via
		(at 259.075682 -314.616592)
		(size 0.4572)
		(drill 0.2032)
		(layers "F.Cu" "B.Cu")
		(net "GND")
	)
	(via
		(at 338.074762 -255.547622)
		(size 0.4572)
		(drill 0.2032)
		(layers "F.Cu" "B.Cu")
		(net "GND")
	)
	(via
		(at 458.455014 -300.166786)
		(size 0.4572)
		(drill 0.2032)
		(layers "F.Cu" "B.Cu")
		(net "GND")
	)
	(via
		(at 169.352214 -269.566644)
		(size 0.4572)
		(drill 0.2032)
		(layers "F.Cu" "B.Cu")
		(net "GND")
	)
	(via
		(at 338.904834 -216.25052)
		(size 0.4572)
		(drill 0.2032)
		(layers "F.Cu" "B.Cu")
		(net "GND")
	)
	(via
		(at 92.484448 -287.28924)
		(size 0.4572)
		(drill 0.2032)
		(layers "F.Cu" "B.Cu")
		(net "GND")
	)
	(via
		(at 122.917712 -229.272846)
		(size 0.4572)
		(drill 0.2032)
		(layers "F.Cu" "B.Cu")
		(net "GND")
	)
	(via
		(at 16.789146 -195.616576)
		(size 0.4572)
		(drill 0.2032)
		(layers "F.Cu" "B.Cu")
		(net "GND")
	)
	(via
		(at 396.619476 -148.410168)
		(size 0.508)
		(drill 0.254)
		(layers "F.Cu" "B.Cu")
		(net "GND")
	)
	(via
		(at 252.29947 -43.422062)
		(size 0.508)
		(drill 0.254)
		(layers "F.Cu" "B.Cu")
		(net "GND")
	)
	(via
		(at 356.761034 -219.506038)
		(size 0.4572)
		(drill 0.2032)
		(layers "F.Cu" "B.Cu")
		(net "GND")
	)
	(via
		(at 311.666382 -312.91657)
		(size 0.4572)
		(drill 0.2032)
		(layers "F.Cu" "B.Cu")
		(net "GND")
	)
	(via
		(at 285.413196 -359.393744)
		(size 0.508)
		(drill 0.254)
		(layers "F.Cu" "B.Cu")
		(net "GND")
	)
	(via
		(at 50.561494 -352.397822)
		(size 0.49022)
		(drill 0.254)
		(layers "F.Cu" "B.Cu")
		(net "GND")
	)
	(via
		(at 460.664814 -315.46673)
		(size 0.4572)
		(drill 0.2032)
		(layers "F.Cu" "B.Cu")
		(net "GND")
	)
	(via
		(at 253.08941 -45.859192)
		(size 0.508)
		(drill 0.254)
		(layers "F.Cu" "B.Cu")
		(net "GND")
	)
	(via
		(at 348.772734 -220.319854)
		(size 0.4572)
		(drill 0.2032)
		(layers "F.Cu" "B.Cu")
		(net "GND")
	)
	(via
		(at 262.519414 -273.816572)
		(size 0.4572)
		(drill 0.2032)
		(layers "F.Cu" "B.Cu")
		(net "GND")
	)
	(via
		(at 230.984044 -56.964834)
		(size 0.508)
		(drill 0.254)
		(layers "F.Cu" "B.Cu")
		(net "GND")
	)
	(via
		(at 62.051946 -315.46673)
		(size 0.4572)
		(drill 0.2032)
		(layers "F.Cu" "B.Cu")
		(net "GND")
	)
	(via
		(at 145.809462 -409.396184)
		(size 0.4572)
		(drill 0.254)
		(layers "F.Cu" "B.Cu")
		(net "GND")
	)
	(via
		(at 338.074762 -281.59202)
		(size 0.4572)
		(drill 0.2032)
		(layers "F.Cu" "B.Cu")
		(net "GND")
	)
	(via
		(at 26.223214 -215.166702)
		(size 0.4572)
		(drill 0.2032)
		(layers "F.Cu" "B.Cu")
		(net "GND")
	)
	(via
		(at 32.561022 -168.15181)
		(size 0.508)
		(drill 0.254)
		(layers "F.Cu" "B.Cu")
		(net "GND")
	)
	(via
		(at 445.577214 -248.31675)
		(size 0.4572)
		(drill 0.2032)
		(layers "F.Cu" "B.Cu")
		(net "GND")
	)
	(via
		(at 202.971146 -309.51678)
		(size 0.4572)
		(drill 0.2032)
		(layers "F.Cu" "B.Cu")
		(net "GND")
	)
	(via
		(at 72.288146 -401.492212)
		(size 0.4572)
		(drill 0.254)
		(layers "F.Cu" "B.Cu")
		(net "GND")
	)
	(via
		(at 343.133934 -213.732618)
		(size 0.4572)
		(drill 0.2032)
		(layers "F.Cu" "B.Cu")
		(net "GND")
	)
	(via
		(at 344.950796 -406.370536)
		(size 0.4572)
		(drill 0.254)
		(layers "F.Cu" "B.Cu")
		(net "GND")
	)
	(via
		(at 424.181016 -136.41451)
		(size 0.508)
		(drill 0.254)
		(layers "F.Cu" "B.Cu")
		(net "GND")
	)
	(via
		(at 11.135614 -230.466646)
		(size 0.4572)
		(drill 0.2032)
		(layers "F.Cu" "B.Cu")
		(net "GND")
	)
	(via
		(at 362.37672 -407.228548)
		(size 0.508)
		(drill 0.254)
		(layers "F.Cu" "B.Cu")
		(net "GND")
	)
	(via
		(at 442.185044 -125.46584)
		(size 0.508)
		(drill 0.254)
		(layers "F.Cu" "B.Cu")
		(net "GND")
	)
	(via
		(at 210.514946 -220.266768)
		(size 0.4572)
		(drill 0.2032)
		(layers "F.Cu" "B.Cu")
		(net "GND")
	)
	(via
		(at 108.820966 -226.017328)
		(size 0.4572)
		(drill 0.2032)
		(layers "F.Cu" "B.Cu")
		(net "GND")
	)
	(via
		(at 291.460682 -308.666642)
		(size 0.4572)
		(drill 0.2032)
		(layers "F.Cu" "B.Cu")
		(net "GND")
	)
	(via
		(at 449.677282 -238.116618)
		(size 0.4572)
		(drill 0.2032)
		(layers "F.Cu" "B.Cu")
		(net "GND")
	)
	(via
		(at 57.847484 -323.434456)
		(size 0.4572)
		(drill 0.2032)
		(layers "F.Cu" "B.Cu")
		(net "GND")
	)
	(via
		(at 175.005746 -234.716574)
		(size 0.4572)
		(drill 0.2032)
		(layers "F.Cu" "B.Cu")
		(net "GND")
	)
	(via
		(at 281.707082 -241.516662)
		(size 0.4572)
		(drill 0.2032)
		(layers "F.Cu" "B.Cu")
		(net "GND")
	)
	(via
		(at 126.207266 -247.992138)
		(size 0.4572)
		(drill 0.2032)
		(layers "F.Cu" "B.Cu")
		(net "GND")
	)
	(via
		(at 435.823614 -221.96679)
		(size 0.4572)
		(drill 0.2032)
		(layers "F.Cu" "B.Cu")
		(net "GND")
	)
	(via
		(at 7.035546 -240.666778)
		(size 0.4572)
		(drill 0.2032)
		(layers "F.Cu" "B.Cu")
		(net "GND")
	)
	(via
		(at 358.280462 -282.405836)
		(size 0.4572)
		(drill 0.2032)
		(layers "F.Cu" "B.Cu")
		(net "GND")
	)
	(via
		(at 386.047234 -250.155964)
		(size 0.4572)
		(drill 0.2032)
		(layers "F.Cu" "B.Cu")
		(net "GND")
	)
	(via
		(at 380.646686 -12.544552)
		(size 0.508)
		(drill 0.254)
		(layers "F.Cu" "B.Cu")
		(net "GND")
	)
	(via
		(at 420.736014 -317.166752)
		(size 0.4572)
		(drill 0.2032)
		(layers "F.Cu" "B.Cu")
		(net "GND")
	)
	(via
		(at 372.377462 -257.98907)
		(size 0.4572)
		(drill 0.2032)
		(layers "F.Cu" "B.Cu")
		(net "GND")
	)
	(via
		(at 113.519966 -222.761556)
		(size 0.4572)
		(drill 0.2032)
		(layers "F.Cu" "B.Cu")
		(net "GND")
	)
	(via
		(at 184.439814 -288.266632)
		(size 0.4572)
		(drill 0.2032)
		(layers "F.Cu" "B.Cu")
		(net "GND")
	)
	(via
		(at 101.835204 -356.160578)
		(size 0.508)
		(drill 0.254)
		(layers "F.Cu" "B.Cu")
		(net "GND")
	)
	(via
		(at 161.808414 -301.01667)
		(size 0.4572)
		(drill 0.2032)
		(layers "F.Cu" "B.Cu")
		(net "GND")
	)
	(via
		(at 257.683 -67.020948)
		(size 0.508)
		(drill 0.254)
		(layers "F.Cu" "B.Cu")
		(net "GND")
	)
	(via
		(at 182.549546 -220.266768)
		(size 0.4572)
		(drill 0.2032)
		(layers "F.Cu" "B.Cu")
		(net "GND")
	)
	(via
		(at 458.455014 -292.516814)
		(size 0.4572)
		(drill 0.2032)
		(layers "F.Cu" "B.Cu")
		(net "GND")
	)
	(via
		(at 430.623218 -182.71363)
		(size 0.508)
		(drill 0.254)
		(layers "F.Cu" "B.Cu")
		(net "GND")
	)
	(via
		(at 438.033414 -281.466798)
		(size 0.4572)
		(drill 0.2032)
		(layers "F.Cu" "B.Cu")
		(net "GND")
	)
	(via
		(at 462.555082 -226.216718)
		(size 0.4572)
		(drill 0.2032)
		(layers "F.Cu" "B.Cu")
		(net "GND")
	)
	(via
		(at 121.617994 -287.28924)
		(size 0.4572)
		(drill 0.2032)
		(layers "F.Cu" "B.Cu")
		(net "GND")
	)
	(via
		(at 369.918234 -237.411514)
		(size 0.4572)
		(drill 0.2032)
		(layers "F.Cu" "B.Cu")
		(net "GND")
	)
	(via
		(at 403.203918 -407.638504)
		(size 0.4572)
		(drill 0.254)
		(layers "F.Cu" "B.Cu")
		(net "GND")
	)
	(via
		(at 337.604862 -259.616956)
		(size 0.4572)
		(drill 0.2032)
		(layers "F.Cu" "B.Cu")
		(net "GND")
	)
	(via
		(at 285.150814 -204.96657)
		(size 0.4572)
		(drill 0.2032)
		(layers "F.Cu" "B.Cu")
		(net "GND")
	)
	(via
		(at 72.662034 -7.215124)
		(size 0.508)
		(drill 0.254)
		(layers "F.Cu" "B.Cu")
		(net "GND")
	)
	(via
		(at 388.349998 -426.54728)
		(size 0.4572)
		(drill 0.2032)
		(layers "F.Cu" "B.Cu")
		(net "GND")
	)
	(via
		(at 309.57774 -429.699928)
		(size 0.508)
		(drill 0.254)
		(layers "F.Cu" "B.Cu")
		(net "GND")
	)
	(via
		(at 302.448214 -260.21665)
		(size 0.4572)
		(drill 0.2032)
		(layers "F.Cu" "B.Cu")
		(net "GND")
	)
	(via
		(at 270.063214 -221.96679)
		(size 0.4572)
		(drill 0.2032)
		(layers "F.Cu" "B.Cu")
		(net "GND")
	)
	(via
		(at 84.385912 -242.294918)
		(size 0.4572)
		(drill 0.2032)
		(layers "F.Cu" "B.Cu")
		(net "GND")
	)
	(via
		(at 445.577214 -292.516814)
		(size 0.4572)
		(drill 0.2032)
		(layers "F.Cu" "B.Cu")
		(net "GND")
	)
	(via
		(at 292.694614 -206.666592)
		(size 0.4572)
		(drill 0.2032)
		(layers "F.Cu" "B.Cu")
		(net "GND")
	)
	(via
		(at 184.439814 -228.766624)
		(size 0.4572)
		(drill 0.2032)
		(layers "F.Cu" "B.Cu")
		(net "GND")
	)
	(via
		(at 447.94678 -176.070768)
		(size 0.508)
		(drill 0.254)
		(layers "F.Cu" "B.Cu")
		(net "GND")
	)
	(via
		(at 179.105814 -230.466646)
		(size 0.4572)
		(drill 0.2032)
		(layers "F.Cu" "B.Cu")
		(net "GND")
	)
	(via
		(at 194.193414 -235.566712)
		(size 0.4572)
		(drill 0.2032)
		(layers "F.Cu" "B.Cu")
		(net "GND")
	)
	(via
		(at 247.824752 -38.8493)
		(size 0.508)
		(drill 0.254)
		(layers "F.Cu" "B.Cu")
		(net "GND")
	)
	(via
		(at 307.782214 -199.01662)
		(size 0.4572)
		(drill 0.2032)
		(layers "F.Cu" "B.Cu")
		(net "GND")
	)
	(via
		(at 372.377462 -275.8948)
		(size 0.4572)
		(drill 0.2032)
		(layers "F.Cu" "B.Cu")
		(net "GND")
	)
	(via
		(at 307.782214 -231.316784)
		(size 0.4572)
		(drill 0.2032)
		(layers "F.Cu" "B.Cu")
		(net "GND")
	)
	(via
		(at 339.484462 -284.033722)
		(size 0.4572)
		(drill 0.2032)
		(layers "F.Cu" "B.Cu")
		(net "GND")
	)
	(via
		(at 372.947184 -331.08392)
		(size 0.508)
		(drill 0.254)
		(layers "F.Cu" "B.Cu")
		(net "GND")
	)
	(via
		(at 374.288558 -404.51786)
		(size 0.4572)
		(drill 0.254)
		(layers "F.Cu" "B.Cu")
		(net "GND")
	)
	(via
		(at 371.662706 -175.130968)
		(size 0.508)
		(drill 0.254)
		(layers "F.Cu" "B.Cu")
		(net "GND")
	)
	(via
		(at 144.74952 -76.451968)
		(size 0.508)
		(drill 0.254)
		(layers "F.Cu" "B.Cu")
		(net "GND")
	)
	(via
		(at 264.729214 -195.616576)
		(size 0.4572)
		(drill 0.2032)
		(layers "F.Cu" "B.Cu")
		(net "GND")
	)
	(via
		(at 307.361336 -56.987948)
		(size 0.508)
		(drill 0.254)
		(layers "F.Cu" "B.Cu")
		(net "GND")
	)
	(via
		(at 139.364212 -234.970066)
		(size 0.4572)
		(drill 0.2032)
		(layers "F.Cu" "B.Cu")
		(net "GND")
	)
	(via
		(at 145.28546 -127.265684)
		(size 0.508)
		(drill 0.254)
		(layers "F.Cu" "B.Cu")
		(net "GND")
	)
	(via
		(at 262.519414 -276.366732)
		(size 0.4572)
		(drill 0.2032)
		(layers "F.Cu" "B.Cu")
		(net "GND")
	)
	(via
		(at 453.121014 -263.616694)
		(size 0.4572)
		(drill 0.2032)
		(layers "F.Cu" "B.Cu")
		(net "GND")
	)
	(via
		(at 9.245346 -267.016738)
		(size 0.4572)
		(drill 0.2032)
		(layers "F.Cu" "B.Cu")
		(net "GND")
	)
	(via
		(at 434.813964 -441.225432)
		(size 0.508)
		(drill 0.254)
		(layers "F.Cu" "B.Cu")
		(net "GND")
	)
	(via
		(at 67.250056 -429.147224)
		(size 0.4572)
		(drill 0.2032)
		(layers "F.Cu" "B.Cu")
		(net "GND")
	)
	(via
		(at 348.47784 -364.787688)
		(size 0.508)
		(drill 0.254)
		(layers "F.Cu" "B.Cu")
		(net "GND")
	)
	(via
		(at 180.339746 -279.766776)
		(size 0.4572)
		(drill 0.2032)
		(layers "F.Cu" "B.Cu")
		(net "GND")
	)
	(via
		(at 350.182434 -219.506038)
		(size 0.4572)
		(drill 0.2032)
		(layers "F.Cu" "B.Cu")
		(net "GND")
	)
	(via
		(at 130.906012 -243.108988)
		(size 0.4572)
		(drill 0.2032)
		(layers "F.Cu" "B.Cu")
		(net "GND")
	)
	(via
		(at 462.555082 -267.866622)
		(size 0.4572)
		(drill 0.2032)
		(layers "F.Cu" "B.Cu")
		(net "GND")
	)
	(via
		(at 126.083822 -400.224244)
		(size 0.4572)
		(drill 0.254)
		(layers "F.Cu" "B.Cu")
		(net "GND")
	)
	(via
		(at 94.363794 -284.033722)
		(size 0.4572)
		(drill 0.2032)
		(layers "F.Cu" "B.Cu")
		(net "GND")
	)
	(via
		(at 240.2332 -109.845602)
		(size 0.508)
		(drill 0.254)
		(layers "F.Cu" "B.Cu")
		(net "GND")
	)
	(via
		(at 403.589998 -5.585714)
		(size 0.508)
		(drill 0.254)
		(layers "F.Cu" "B.Cu")
		(net "GND")
	)
	(via
		(at 371.437662 -284.033722)
		(size 0.4572)
		(drill 0.2032)
		(layers "F.Cu" "B.Cu")
		(net "GND")
	)
	(via
		(at 130.350006 -429.147224)
		(size 0.4572)
		(drill 0.2032)
		(layers "F.Cu" "B.Cu")
		(net "GND")
	)
	(via
		(at 54.12105 -350.915732)
		(size 0.508)
		(drill 0.254)
		(layers "F.Cu" "B.Cu")
		(net "GND")
	)
	(via
		(at 59.250072 -435.0512)
		(size 0.4572)
		(drill 0.2032)
		(layers "F.Cu" "B.Cu")
		(net "GND")
	)
	(via
		(at 214.615014 -267.866622)
		(size 0.4572)
		(drill 0.2032)
		(layers "F.Cu" "B.Cu")
		(net "GND")
	)
	(via
		(at 411.958282 -202.416664)
		(size 0.4572)
		(drill 0.2032)
		(layers "F.Cu" "B.Cu")
		(net "GND")
	)
	(via
		(at 346.667836 -404.51786)
		(size 0.4572)
		(drill 0.254)
		(layers "F.Cu" "B.Cu")
		(net "GND")
	)
	(via
		(at 440.661552 -323.429376)
		(size 0.4572)
		(drill 0.2032)
		(layers "F.Cu" "B.Cu")
		(net "GND")
	)
	(via
		(at 294.417496 -360.833924)
		(size 0.508)
		(drill 0.254)
		(layers "F.Cu" "B.Cu")
		(net "GND")
	)
	(via
		(at 50.845466 -401.492212)
		(size 0.4572)
		(drill 0.254)
		(layers "F.Cu" "B.Cu")
		(net "GND")
	)
	(via
		(at 87.484966 -335.976214)
		(size 0.49022)
		(drill 0.254)
		(layers "F.Cu" "B.Cu")
		(net "GND")
	)
	(via
		(at 14.579346 -298.466764)
		(size 0.4572)
		(drill 0.2032)
		(layers "F.Cu" "B.Cu")
		(net "GND")
	)
	(via
		(at 177.95494 -14.676628)
		(size 0.508)
		(drill 0.254)
		(layers "F.Cu" "B.Cu")
		(net "GND")
	)
	(via
		(at 386.350002 -436.347362)
		(size 0.4572)
		(drill 0.2032)
		(layers "F.Cu" "B.Cu")
		(net "GND")
	)
	(via
		(at 11.387582 -421.616886)
		(size 0.508)
		(drill 0.254)
		(layers "F.Cu" "B.Cu")
		(net "GND")
	)
	(via
		(at 132.476494 -139.908026)
		(size 0.508)
		(drill 0.254)
		(layers "F.Cu" "B.Cu")
		(net "GND")
	)
	(via
		(at 22.123146 -242.3668)
		(size 0.4572)
		(drill 0.2032)
		(layers "F.Cu" "B.Cu")
		(net "GND")
	)
	(via
		(at 56.049672 -145.829274)
		(size 0.49022)
		(drill 0.254)
		(layers "F.Cu" "B.Cu")
		(net "GND")
	)
	(via
		(at 92.484448 -282.405836)
		(size 0.4572)
		(drill 0.2032)
		(layers "F.Cu" "B.Cu")
		(net "GND")
	)
	(via
		(at 187.273946 -194.789298)
		(size 0.508)
		(drill 0.254)
		(layers "F.Cu" "B.Cu")
		(net "GND")
	)
	(via
		(at 157.349952 -433.747164)
		(size 0.4572)
		(drill 0.2032)
		(layers "F.Cu" "B.Cu")
		(net "GND")
	)
	(via
		(at 56.049672 -147.810474)
		(size 0.49022)
		(drill 0.254)
		(layers "F.Cu" "B.Cu")
		(net "GND")
	)
	(via
		(at 212.724746 -292.516814)
		(size 0.4572)
		(drill 0.2032)
		(layers "F.Cu" "B.Cu")
		(net "GND")
	)
	(via
		(at 134.067042 -33.477708)
		(size 0.508)
		(drill 0.254)
		(layers "F.Cu" "B.Cu")
		(net "GND")
	)
	(via
		(at 274.163282 -275.516594)
		(size 0.4572)
		(drill 0.2032)
		(layers "F.Cu" "B.Cu")
		(net "GND")
	)
	(via
		(at 420.736014 -285.716726)
		(size 0.4572)
		(drill 0.2032)
		(layers "F.Cu" "B.Cu")
		(net "GND")
	)
	(via
		(at 71.250048 -426.69968)
		(size 0.4572)
		(drill 0.2032)
		(layers "F.Cu" "B.Cu")
		(net "GND")
	)
	(via
		(at 297.90771 -53.384196)
		(size 0.508)
		(drill 0.254)
		(layers "F.Cu" "B.Cu")
		(net "GND")
	)
	(via
		(at 110.23092 -247.992392)
		(size 0.4572)
		(drill 0.2032)
		(layers "F.Cu" "B.Cu")
		(net "GND")
	)
	(via
		(at 37.210746 -199.01662)
		(size 0.4572)
		(drill 0.2032)
		(layers "F.Cu" "B.Cu")
		(net "GND")
	)
	(via
		(at 135.35533 -441.225432)
		(size 0.508)
		(drill 0.254)
		(layers "F.Cu" "B.Cu")
		(net "GND")
	)
	(via
		(at 415.307018 -149.312376)
		(size 0.508)
		(drill 0.254)
		(layers "F.Cu" "B.Cu")
		(net "GND")
	)
	(via
		(at 264.729214 -248.31675)
		(size 0.4572)
		(drill 0.2032)
		(layers "F.Cu" "B.Cu")
		(net "GND")
	)
	(via
		(at 125.267466 -223.575626)
		(size 0.4572)
		(drill 0.2032)
		(layers "F.Cu" "B.Cu")
		(net "GND")
	)
	(via
		(at 336.665062 -257.98907)
		(size 0.4572)
		(drill 0.2032)
		(layers "F.Cu" "B.Cu")
		(net "GND")
	)
	(via
		(at 91.904566 -216.25052)
		(size 0.4572)
		(drill 0.2032)
		(layers "F.Cu" "B.Cu")
		(net "GND")
	)
	(via
		(at 210.514946 -210.916774)
		(size 0.4572)
		(drill 0.2032)
		(layers "F.Cu" "B.Cu")
		(net "GND")
	)
	(via
		(at 376.606816 -275.08073)
		(size 0.4572)
		(drill 0.2032)
		(layers "F.Cu" "B.Cu")
		(net "GND")
	)
	(via
		(at 268.29512 -152.712928)
		(size 0.508)
		(drill 0.254)
		(layers "F.Cu" "B.Cu")
		(net "GND")
	)
	(via
		(at 223.251014 -127.968502)
		(size 0.508)
		(drill 0.254)
		(layers "F.Cu" "B.Cu")
		(net "GND")
	)
	(via
		(at 272.273014 -258.516628)
		(size 0.4572)
		(drill 0.2032)
		(layers "F.Cu" "B.Cu")
		(net "GND")
	)
	(via
		(at 171.562014 -264.466578)
		(size 0.4572)
		(drill 0.2032)
		(layers "F.Cu" "B.Cu")
		(net "GND")
	)
	(via
		(at 326.48398 -403.249892)
		(size 0.4572)
		(drill 0.254)
		(layers "F.Cu" "B.Cu")
		(net "GND")
	)
	(via
		(at 52.298346 -309.51678)
		(size 0.4572)
		(drill 0.2032)
		(layers "F.Cu" "B.Cu")
		(net "GND")
	)
	(via
		(at 150.131526 -406.370536)
		(size 0.4572)
		(drill 0.254)
		(layers "F.Cu" "B.Cu")
		(net "GND")
	)
	(via
		(at 310.82488 -55.336948)
		(size 0.508)
		(drill 0.254)
		(layers "F.Cu" "B.Cu")
		(net "GND")
	)
	(via
		(at 287.360614 -268.71676)
		(size 0.4572)
		(drill 0.2032)
		(layers "F.Cu" "B.Cu")
		(net "GND")
	)
	(via
		(at 163.63823 -122.646948)
		(size 0.508)
		(drill 0.254)
		(layers "F.Cu" "B.Cu")
		(net "GND")
	)
	(via
		(at 7.264654 -421.015414)
		(size 0.508)
		(drill 0.254)
		(layers "F.Cu" "B.Cu")
		(net "GND")
	)
	(via
		(at 343.550494 -49.389792)
		(size 0.4572)
		(drill 0.2032)
		(layers "F.Cu" "B.Cu")
		(net "GND")
	)
	(via
		(at 344.589608 -407.00452)
		(size 0.4064)
		(drill 0.2032)
		(layers "F.Cu" "B.Cu")
		(net "GND")
	)
	(via
		(at 22.18309 -18.246344)
		(size 0.508)
		(drill 0.254)
		(layers "F.Cu" "B.Cu")
		(net "GND")
	)
	(via
		(at 128.35001 -428.851314)
		(size 0.4572)
		(drill 0.2032)
		(layers "F.Cu" "B.Cu")
		(net "GND")
	)
	(via
		(at 94.833694 -289.807142)
		(size 0.4572)
		(drill 0.2032)
		(layers "F.Cu" "B.Cu")
		(net "GND")
	)
	(via
		(at 341.724234 -232.528364)
		(size 0.4572)
		(drill 0.2032)
		(layers "F.Cu" "B.Cu")
		(net "GND")
	)
	(via
		(at 34.08807 -163.475162)
		(size 0.508)
		(drill 0.254)
		(layers "F.Cu" "B.Cu")
		(net "GND")
	)
	(via
		(at 109.06633 -61.102748)
		(size 0.508)
		(drill 0.254)
		(layers "F.Cu" "B.Cu")
		(net "GND")
	)
	(via
		(at 257.185414 -289.11677)
		(size 0.4572)
		(drill 0.2032)
		(layers "F.Cu" "B.Cu")
		(net "GND")
	)
	(via
		(at 443.367414 -298.466764)
		(size 0.4572)
		(drill 0.2032)
		(layers "F.Cu" "B.Cu")
		(net "GND")
	)
	(via
		(at 341.724234 -216.25052)
		(size 0.4572)
		(drill 0.2032)
		(layers "F.Cu" "B.Cu")
		(net "GND")
	)
	(via
		(at 104.3178 -421.24884)
		(size 0.508)
		(drill 0.254)
		(layers "F.Cu" "B.Cu")
		(net "GND")
	)
	(via
		(at 292.980618 -148.961348)
		(size 0.508)
		(drill 0.254)
		(layers "F.Cu" "B.Cu")
		(net "GND")
	)
	(via
		(at 334.315562 -283.219906)
		(size 0.4572)
		(drill 0.2032)
		(layers "F.Cu" "B.Cu")
		(net "GND")
	)
	(via
		(at 306.548282 -305.266598)
		(size 0.4572)
		(drill 0.2032)
		(layers "F.Cu" "B.Cu")
		(net "GND")
	)
	(via
		(at 362.979462 -269.38351)
		(size 0.4572)
		(drill 0.2032)
		(layers "F.Cu" "B.Cu")
		(net "GND")
	)
	(via
		(at 255.651 -68.544948)
		(size 0.508)
		(drill 0.254)
		(layers "F.Cu" "B.Cu")
		(net "GND")
	)
	(via
		(at 180.86324 -345.64701)
		(size 0.508)
		(drill 0.254)
		(layers "F.Cu" "B.Cu")
		(net "GND")
	)
	(via
		(at 278.380952 -323.429376)
		(size 0.4572)
		(drill 0.2032)
		(layers "F.Cu" "B.Cu")
		(net "GND")
	)
	(via
		(at 374.726962 -286.475424)
		(size 0.4572)
		(drill 0.2032)
		(layers "F.Cu" "B.Cu")
		(net "GND")
	)
	(via
		(at 39.420546 -210.916774)
		(size 0.4572)
		(drill 0.2032)
		(layers "F.Cu" "B.Cu")
		(net "GND")
	)
	(via
		(at 347.363034 -248.806208)
		(size 0.4572)
		(drill 0.2032)
		(layers "F.Cu" "B.Cu")
		(net "GND")
	)
	(via
		(at 157.349952 -438.499758)
		(size 0.4572)
		(drill 0.2032)
		(layers "F.Cu" "B.Cu")
		(net "GND")
	)
	(via
		(at 325.250048 -427.699678)
		(size 0.4572)
		(drill 0.2032)
		(layers "F.Cu" "B.Cu")
		(net "GND")
	)
	(via
		(at 386.103876 -77.861922)
		(size 0.508)
		(drill 0.254)
		(layers "F.Cu" "B.Cu")
		(net "GND")
	)
	(via
		(at 422.945814 -260.21665)
		(size 0.4572)
		(drill 0.2032)
		(layers "F.Cu" "B.Cu")
		(net "GND")
	)
	(via
		(at 207.37068 -72.913748)
		(size 0.508)
		(drill 0.254)
		(layers "F.Cu" "B.Cu")
		(net "GND")
	)
	(via
		(at 179.105814 -239.81664)
		(size 0.4572)
		(drill 0.2032)
		(layers "F.Cu" "B.Cu")
		(net "GND")
	)
	(via
		(at 347.36278 -227.64496)
		(size 0.4572)
		(drill 0.2032)
		(layers "F.Cu" "B.Cu")
		(net "GND")
	)
	(via
		(at 45.657008 -9.424924)
		(size 0.508)
		(drill 0.254)
		(layers "F.Cu" "B.Cu")
		(net "GND")
	)
	(via
		(at 409.748482 -266.1666)
		(size 0.4572)
		(drill 0.2032)
		(layers "F.Cu" "B.Cu")
		(net "GND")
	)
	(via
		(at 368.916204 -245.59895)
		(size 0.4572)
		(drill 0.2032)
		(layers "F.Cu" "B.Cu")
		(net "GND")
	)
	(via
		(at 29.590492 -4.962652)
		(size 0.508)
		(drill 0.254)
		(layers "F.Cu" "B.Cu")
		(net "GND")
	)
	(via
		(at 338.250022 -426.54728)
		(size 0.4572)
		(drill 0.2032)
		(layers "F.Cu" "B.Cu")
		(net "GND")
	)
	(via
		(at 331.351636 -400.224244)
		(size 0.4572)
		(drill 0.254)
		(layers "F.Cu" "B.Cu")
		(net "GND")
	)
	(via
		(at 171.24553 -440.019948)
		(size 0.508)
		(drill 0.254)
		(layers "F.Cu" "B.Cu")
		(net "GND")
	)
	(via
		(at 131.829302 -335.1911)
		(size 0.49022)
		(drill 0.254)
		(layers "F.Cu" "B.Cu")
		(net "GND")
	)
	(via
		(at 385.064762 -253.919736)
		(size 0.4318)
		(drill 0.2032)
		(layers "F.Cu" "B.Cu")
		(net "GND")
	)
	(via
		(at 333.510382 -44.221146)
		(size 0.4572)
		(drill 0.2032)
		(layers "F.Cu" "B.Cu")
		(net "GND")
	)
	(via
		(at 317.381636 -409.396184)
		(size 0.4572)
		(drill 0.254)
		(layers "F.Cu" "B.Cu")
		(net "GND")
	)
	(via
		(at 216.824814 -221.116652)
		(size 0.4572)
		(drill 0.2032)
		(layers "F.Cu" "B.Cu")
		(net "GND")
	)
	(via
		(at 127.616966 -229.272846)
		(size 0.4572)
		(drill 0.2032)
		(layers "F.Cu" "B.Cu")
		(net "GND")
	)
	(via
		(at 352.531934 -217.064336)
		(size 0.4572)
		(drill 0.2032)
		(layers "F.Cu" "B.Cu")
		(net "GND")
	)
	(via
		(at 341.918798 -41.871646)
		(size 0.4572)
		(drill 0.2032)
		(layers "F.Cu" "B.Cu")
		(net "GND")
	)
	(via
		(at 105.641648 -275.8948)
		(size 0.4572)
		(drill 0.2032)
		(layers "F.Cu" "B.Cu")
		(net "GND")
	)
	(via
		(at 130.906266 -213.732618)
		(size 0.4572)
		(drill 0.2032)
		(layers "F.Cu" "B.Cu")
		(net "GND")
	)
	(via
		(at 390.563608 -336.779616)
		(size 0.508)
		(drill 0.254)
		(layers "F.Cu" "B.Cu")
		(net "GND")
	)
	(via
		(at 130.546094 -283.219906)
		(size 0.4572)
		(drill 0.2032)
		(layers "F.Cu" "B.Cu")
		(net "GND")
	)
	(via
		(at 49.12614 -434.747924)
		(size 0.508)
		(drill 0.254)
		(layers "F.Cu" "B.Cu")
		(net "GND")
	)
	(via
		(at 279.816814 -281.466798)
		(size 0.4572)
		(drill 0.2032)
		(layers "F.Cu" "B.Cu")
		(net "GND")
	)
	(via
		(at 216.824814 -310.366664)
		(size 0.4572)
		(drill 0.2032)
		(layers "F.Cu" "B.Cu")
		(net "GND")
	)
	(via
		(at 93.423994 -284.033722)
		(size 0.4572)
		(drill 0.2032)
		(layers "F.Cu" "B.Cu")
		(net "GND")
	)
	(via
		(at 257.429 -87.6046)
		(size 0.508)
		(drill 0.254)
		(layers "F.Cu" "B.Cu")
		(net "GND")
	)
	(via
		(at 419.58006 -132.21716)
		(size 0.508)
		(drill 0.254)
		(layers "F.Cu" "B.Cu")
		(net "GND")
	)
	(via
		(at 407.34996 -432.747166)
		(size 0.4572)
		(drill 0.2032)
		(layers "F.Cu" "B.Cu")
		(net "GND")
	)
	(via
		(at 136.184894 -263.686544)
		(size 0.4572)
		(drill 0.2032)
		(layers "F.Cu" "B.Cu")
		(net "GND")
	)
	(via
		(at 172.34281 -399.77314)
		(size 0.508)
		(drill 0.254)
		(layers "F.Cu" "B.Cu")
		(net "GND")
	)
	(via
		(at 33.767014 -297.616626)
		(size 0.4572)
		(drill 0.2032)
		(layers "F.Cu" "B.Cu")
		(net "GND")
	)
	(via
		(at 144.463262 -403.249892)
		(size 0.4572)
		(drill 0.254)
		(layers "F.Cu" "B.Cu")
		(net "GND")
	)
	(via
		(at 214.615014 -233.86669)
		(size 0.4572)
		(drill 0.2032)
		(layers "F.Cu" "B.Cu")
		(net "GND")
	)
	(via
		(at 138.064494 -278.336502)
		(size 0.4572)
		(drill 0.2032)
		(layers "F.Cu" "B.Cu")
		(net "GND")
	)
	(via
		(at 205.180946 -242.3668)
		(size 0.4572)
		(drill 0.2032)
		(layers "F.Cu" "B.Cu")
		(net "GND")
	)
	(via
		(at 184.439814 -235.566712)
		(size 0.4572)
		(drill 0.2032)
		(layers "F.Cu" "B.Cu")
		(net "GND")
	)
	(via
		(at 328.288396 -403.249892)
		(size 0.4572)
		(drill 0.254)
		(layers "F.Cu" "B.Cu")
		(net "GND")
	)
	(via
		(at 380.365762 -253.919736)
		(size 0.4572)
		(drill 0.2032)
		(layers "F.Cu" "B.Cu")
		(net "GND")
	)
	(via
		(at 39.420546 -301.866808)
		(size 0.4572)
		(drill 0.2032)
		(layers "F.Cu" "B.Cu")
		(net "GND")
	)
	(via
		(at 254.975614 -221.96679)
		(size 0.4572)
		(drill 0.2032)
		(layers "F.Cu" "B.Cu")
		(net "GND")
	)
	(via
		(at 115.509548 -271.825212)
		(size 0.4572)
		(drill 0.2032)
		(layers "F.Cu" "B.Cu")
		(net "GND")
	)
	(via
		(at 126.883668 -366.093248)
		(size 0.508)
		(drill 0.254)
		(layers "F.Cu" "B.Cu")
		(net "GND")
	)
	(via
		(at 43.520614 -221.116652)
		(size 0.4572)
		(drill 0.2032)
		(layers "F.Cu" "B.Cu")
		(net "GND")
	)
	(via
		(at 439.923682 -262.76681)
		(size 0.4572)
		(drill 0.2032)
		(layers "F.Cu" "B.Cu")
		(net "GND")
	)
	(via
		(at 300.238414 -258.516628)
		(size 0.4572)
		(drill 0.2032)
		(layers "F.Cu" "B.Cu")
		(net "GND")
	)
	(via
		(at 89.69883 -58.003948)
		(size 0.508)
		(drill 0.254)
		(layers "F.Cu" "B.Cu")
		(net "GND")
	)
	(via
		(at 134.665212 -244.73662)
		(size 0.4572)
		(drill 0.2032)
		(layers "F.Cu" "B.Cu")
		(net "GND")
	)
	(via
		(at 58.591958 -403.883876)
		(size 0.4064)
		(drill 0.2032)
		(layers "F.Cu" "B.Cu")
		(net "GND")
	)
	(via
		(at 24.332946 -233.016806)
		(size 0.4572)
		(drill 0.2032)
		(layers "F.Cu" "B.Cu")
		(net "GND")
	)
	(via
		(at 291.460682 -314.616592)
		(size 0.4572)
		(drill 0.2032)
		(layers "F.Cu" "B.Cu")
		(net "GND")
	)
	(via
		(at 190.093346 -227.066602)
		(size 0.4572)
		(drill 0.2032)
		(layers "F.Cu" "B.Cu")
		(net "GND")
	)
	(via
		(at 308.33314 -429.699928)
		(size 0.508)
		(drill 0.254)
		(layers "F.Cu" "B.Cu")
		(net "GND")
	)
	(via
		(at 31.876746 -267.016738)
		(size 0.4572)
		(drill 0.2032)
		(layers "F.Cu" "B.Cu")
		(net "GND")
	)
	(via
		(at 88.392 -191.861948)
		(size 0.508)
		(drill 0.254)
		(layers "F.Cu" "B.Cu")
		(net "GND")
	)
	(via
		(at 22.123146 -221.96679)
		(size 0.4572)
		(drill 0.2032)
		(layers "F.Cu" "B.Cu")
		(net "GND")
	)
	(via
		(at 2.764536 -107.110022)
		(size 0.508)
		(drill 0.254)
		(layers "F.Cu" "B.Cu")
		(net "GND")
	)
	(via
		(at 387.887718 -409.396184)
		(size 0.4572)
		(drill 0.254)
		(layers "F.Cu" "B.Cu")
		(net "GND")
	)
	(via
		(at 270.063214 -311.216802)
		(size 0.4572)
		(drill 0.2032)
		(layers "F.Cu" "B.Cu")
		(net "GND")
	)
	(via
		(at 382.245616 -266.941808)
		(size 0.4572)
		(drill 0.2032)
		(layers "F.Cu" "B.Cu")
		(net "GND")
	)
	(via
		(at 342.304116 -280.778204)
		(size 0.4572)
		(drill 0.2032)
		(layers "F.Cu" "B.Cu")
		(net "GND")
	)
	(via
		(at 16.789146 -238.966756)
		(size 0.4572)
		(drill 0.2032)
		(layers "F.Cu" "B.Cu")
		(net "GND")
	)
	(via
		(at 51.674014 -345.64066)
		(size 0.508)
		(drill 0.254)
		(layers "F.Cu" "B.Cu")
		(net "GND")
	)
	(via
		(at 2.764536 -173.150022)
		(size 0.508)
		(drill 0.254)
		(layers "F.Cu" "B.Cu")
		(net "GND")
	)
	(via
		(at 18.819114 -6.090412)
		(size 0.508)
		(drill 0.254)
		(layers "F.Cu" "B.Cu")
		(net "GND")
	)
	(via
		(at 176.955704 -110.975394)
		(size 0.4572)
		(drill 0.254)
		(layers "F.Cu" "B.Cu")
		(net "GND")
	)
	(via
		(at 365.689134 -217.064336)
		(size 0.4572)
		(drill 0.2032)
		(layers "F.Cu" "B.Cu")
		(net "GND")
	)
	(via
		(at 89.664794 -256.361438)
		(size 0.4572)
		(drill 0.2032)
		(layers "F.Cu" "B.Cu")
		(net "GND")
	)
	(via
		(at 374.257062 -275.8948)
		(size 0.4572)
		(drill 0.2032)
		(layers "F.Cu" "B.Cu")
		(net "GND")
	)
	(via
		(at 179.105814 -314.616592)
		(size 0.4572)
		(drill 0.2032)
		(layers "F.Cu" "B.Cu")
		(net "GND")
	)
	(via
		(at 28.978098 -76.924916)
		(size 0.508)
		(drill 0.254)
		(layers "F.Cu" "B.Cu")
		(net "GND")
	)
	(via
		(at 56.971946 -404.51786)
		(size 0.4572)
		(drill 0.254)
		(layers "F.Cu" "B.Cu")
		(net "GND")
	)
	(via
		(at 37.210746 -231.316784)
		(size 0.4572)
		(drill 0.2032)
		(layers "F.Cu" "B.Cu")
		(net "GND")
	)
	(via
		(at 414.070292 -179.489354)
		(size 0.49022)
		(drill 0.254)
		(layers "F.Cu" "B.Cu")
		(net "GND")
	)
	(via
		(at 179.105814 -241.516662)
		(size 0.4572)
		(drill 0.2032)
		(layers "F.Cu" "B.Cu")
		(net "GND")
	)
	(via
		(at 381.19558 -247.178322)
		(size 0.4572)
		(drill 0.2032)
		(layers "F.Cu" "B.Cu")
		(net "GND")
	)
	(via
		(at 145.349976 -438.499758)
		(size 0.4572)
		(drill 0.2032)
		(layers "F.Cu" "B.Cu")
		(net "GND")
	)
	(via
		(at 377.697238 -353.57181)
		(size 0.6604)
		(drill 0.3302)
		(layers "F.Cu" "B.Cu")
		(net "GND")
	)
	(via
		(at 292.694614 -225.36658)
		(size 0.4572)
		(drill 0.2032)
		(layers "F.Cu" "B.Cu")
		(net "GND")
	)
	(via
		(at 191.983614 -221.116652)
		(size 0.4572)
		(drill 0.2032)
		(layers "F.Cu" "B.Cu")
		(net "GND")
	)
	(via
		(at 51.467004 -10.16508)
		(size 0.508)
		(drill 0.254)
		(layers "F.Cu" "B.Cu")
		(net "GND")
	)
	(via
		(at 458.455014 -221.96679)
		(size 0.4572)
		(drill 0.2032)
		(layers "F.Cu" "B.Cu")
		(net "GND")
	)
	(via
		(at 170.59148 -424.398948)
		(size 0.508)
		(drill 0.254)
		(layers "F.Cu" "B.Cu")
		(net "GND")
	)
	(via
		(at 427.045882 -291.666676)
		(size 0.4572)
		(drill 0.2032)
		(layers "F.Cu" "B.Cu")
		(net "GND")
	)
	(via
		(at 327.250044 -432.747166)
		(size 0.4572)
		(drill 0.2032)
		(layers "F.Cu" "B.Cu")
		(net "GND")
	)
	(via
		(at 417.292282 -306.96662)
		(size 0.4572)
		(drill 0.2032)
		(layers "F.Cu" "B.Cu")
		(net "GND")
	)
	(via
		(at 124.437394 -282.405836)
		(size 0.4572)
		(drill 0.2032)
		(layers "F.Cu" "B.Cu")
		(net "GND")
	)
	(via
		(at 392.81862 -6.586474)
		(size 0.508)
		(drill 0.254)
		(layers "F.Cu" "B.Cu")
		(net "GND")
	)
	(via
		(at 445.577214 -267.016738)
		(size 0.4572)
		(drill 0.2032)
		(layers "F.Cu" "B.Cu")
		(net "GND")
	)
	(via
		(at 323.508116 -407.638504)
		(size 0.4572)
		(drill 0.254)
		(layers "F.Cu" "B.Cu")
		(net "GND")
	)
	(via
		(at 87.205566 -232.528364)
		(size 0.4572)
		(drill 0.2032)
		(layers "F.Cu" "B.Cu")
		(net "GND")
	)
	(via
		(at 137.93089 -112.01527)
		(size 0.508)
		(drill 0.254)
		(layers "F.Cu" "B.Cu")
		(net "GND")
	)
	(via
		(at 186.649614 -280.61666)
		(size 0.4572)
		(drill 0.2032)
		(layers "F.Cu" "B.Cu")
		(net "GND")
	)
	(via
		(at 279.816814 -263.616694)
		(size 0.4572)
		(drill 0.2032)
		(layers "F.Cu" "B.Cu")
		(net "GND")
	)
	(via
		(at 412.676086 -174.363126)
		(size 0.508)
		(drill 0.254)
		(layers "F.Cu" "B.Cu")
		(net "GND")
	)
	(via
		(at 79.984854 -340.977728)
		(size 0.49022)
		(drill 0.254)
		(layers "F.Cu" "B.Cu")
		(net "GND")
	)
	(via
		(at 419.856412 -17.601438)
		(size 0.508)
		(drill 0.254)
		(layers "F.Cu" "B.Cu")
		(net "GND")
	)
	(via
		(at 87.489284 -187.816236)
		(size 0.508)
		(drill 0.254)
		(layers "F.Cu" "B.Cu")
		(net "GND")
	)
	(via
		(at 165.252146 -246.616728)
		(size 0.4572)
		(drill 0.2032)
		(layers "F.Cu" "B.Cu")
		(net "GND")
	)
	(via
		(at 46.964346 -234.716574)
		(size 0.4572)
		(drill 0.2032)
		(layers "F.Cu" "B.Cu")
		(net "GND")
	)
	(via
		(at 194.193414 -202.416664)
		(size 0.4572)
		(drill 0.2032)
		(layers "F.Cu" "B.Cu")
		(net "GND")
	)
	(via
		(at 337.49488 -243.108988)
		(size 0.4572)
		(drill 0.2032)
		(layers "F.Cu" "B.Cu")
		(net "GND")
	)
	(via
		(at 206.300832 -439.905394)
		(size 0.508)
		(drill 0.254)
		(layers "F.Cu" "B.Cu")
		(net "GND")
	)
	(via
		(at 361.569762 -281.59202)
		(size 0.4572)
		(drill 0.2032)
		(layers "F.Cu" "B.Cu")
		(net "GND")
	)
	(via
		(at 363.339634 -229.272846)
		(size 0.4572)
		(drill 0.2032)
		(layers "F.Cu" "B.Cu")
		(net "GND")
	)
	(via
		(at 351.40392 -22.588728)
		(size 0.508)
		(drill 0.254)
		(layers "F.Cu" "B.Cu")
		(net "GND")
	)
	(via
		(at 270.063214 -229.616762)
		(size 0.4572)
		(drill 0.2032)
		(layers "F.Cu" "B.Cu")
		(net "GND")
	)
	(via
		(at 337.604862 -257.98907)
		(size 0.4572)
		(drill 0.2032)
		(layers "F.Cu" "B.Cu")
		(net "GND")
	)
	(via
		(at 427.045882 -264.466578)
		(size 0.4572)
		(drill 0.2032)
		(layers "F.Cu" "B.Cu")
		(net "GND")
	)
	(via
		(at 146.96948 -11.458448)
		(size 0.508)
		(drill 0.254)
		(layers "F.Cu" "B.Cu")
		(net "GND")
	)
	(via
		(at 415.369502 -403.249892)
		(size 0.4572)
		(drill 0.254)
		(layers "F.Cu" "B.Cu")
		(net "GND")
	)
	(via
		(at 48.854614 -230.466646)
		(size 0.4572)
		(drill 0.2032)
		(layers "F.Cu" "B.Cu")
		(net "GND")
	)
	(via
		(at 53.908706 -404.51786)
		(size 0.4572)
		(drill 0.254)
		(layers "F.Cu" "B.Cu")
		(net "GND")
	)
	(via
		(at 375.557034 -237.411514)
		(size 0.4572)
		(drill 0.2032)
		(layers "F.Cu" "B.Cu")
		(net "GND")
	)
	(via
		(at 46.964346 -242.3668)
		(size 0.4572)
		(drill 0.2032)
		(layers "F.Cu" "B.Cu")
		(net "GND")
	)
	(via
		(at 175.038512 -419.674548)
		(size 0.508)
		(drill 0.254)
		(layers "F.Cu" "B.Cu")
		(net "GND")
	)
	(via
		(at 448.29857 -76.695554)
		(size 0.508)
		(drill 0.254)
		(layers "F.Cu" "B.Cu")
		(net "GND")
	)
	(via
		(at 117.963442 -332.363826)
		(size 0.508)
		(drill 0.254)
		(layers "F.Cu" "B.Cu")
		(net "GND")
	)
	(via
		(at 205.180946 -246.616728)
		(size 0.4572)
		(drill 0.2032)
		(layers "F.Cu" "B.Cu")
		(net "GND")
	)
	(via
		(at 139.553188 -270.4719)
		(size 0.4572)
		(drill 0.2032)
		(layers "F.Cu" "B.Cu")
		(net "GND")
	)
	(via
		(at 358.640634 -222.761556)
		(size 0.4572)
		(drill 0.2032)
		(layers "F.Cu" "B.Cu")
		(net "GND")
	)
	(via
		(at 202.971146 -238.966756)
		(size 0.4572)
		(drill 0.2032)
		(layers "F.Cu" "B.Cu")
		(net "GND")
	)
	(via
		(at 335.138268 -43.281346)
		(size 0.4572)
		(drill 0.2032)
		(layers "F.Cu" "B.Cu")
		(net "GND")
	)
	(via
		(at 377.351798 -400.224244)
		(size 0.4572)
		(drill 0.254)
		(layers "F.Cu" "B.Cu")
		(net "GND")
	)
	(via
		(at 66.2178 -55.540148)
		(size 0.508)
		(drill 0.254)
		(layers "F.Cu" "B.Cu")
		(net "GND")
	)
	(via
		(at 33.767014 -266.1666)
		(size 0.4572)
		(drill 0.2032)
		(layers "F.Cu" "B.Cu")
		(net "GND")
	)
	(via
		(at 18.679414 -275.516594)
		(size 0.4572)
		(drill 0.2032)
		(layers "F.Cu" "B.Cu")
		(net "GND")
	)
	(via
		(at 176.896014 -301.01667)
		(size 0.4572)
		(drill 0.2032)
		(layers "F.Cu" "B.Cu")
		(net "GND")
	)
	(via
		(at 462.555082 -316.316614)
		(size 0.4572)
		(drill 0.2032)
		(layers "F.Cu" "B.Cu")
		(net "GND")
	)
	(via
		(at 449.677282 -314.616592)
		(size 0.4572)
		(drill 0.2032)
		(layers "F.Cu" "B.Cu")
		(net "GND")
	)
	(via
		(at 356.51186 -390.43737)
		(size 0.508)
		(drill 0.254)
		(layers "F.Cu" "B.Cu")
		(net "GND")
	)
	(via
		(at 311.882282 -249.166634)
		(size 0.4572)
		(drill 0.2032)
		(layers "F.Cu" "B.Cu")
		(net "GND")
	)
	(via
		(at 460.664814 -244.916706)
		(size 0.4572)
		(drill 0.2032)
		(layers "F.Cu" "B.Cu")
		(net "GND")
	)
	(via
		(at 130.268726 -335.187036)
		(size 0.49022)
		(drill 0.254)
		(layers "F.Cu" "B.Cu")
		(net "GND")
	)
	(via
		(at 376.26544 -91.133168)
		(size 0.508)
		(drill 0.254)
		(layers "F.Cu" "B.Cu")
		(net "GND")
	)
	(via
		(at 380.758192 -335.266284)
		(size 0.508)
		(drill 0.254)
		(layers "F.Cu" "B.Cu")
		(net "GND")
	)
	(via
		(at 371.288564 -326.948292)
		(size 0.508)
		(drill 0.254)
		(layers "F.Cu" "B.Cu")
		(net "GND")
	)
	(via
		(at 323.250052 -435.0512)
		(size 0.4572)
		(drill 0.2032)
		(layers "F.Cu" "B.Cu")
		(net "GND")
	)
	(via
		(at 367.488978 -330.53909)
		(size 0.6604)
		(drill 0.3302)
		(layers "F.Cu" "B.Cu")
		(net "GND")
	)
	(via
		(at 311.882282 -205.816708)
		(size 0.4572)
		(drill 0.2032)
		(layers "F.Cu" "B.Cu")
		(net "GND")
	)
	(via
		(at 195.427346 -289.11677)
		(size 0.4572)
		(drill 0.2032)
		(layers "F.Cu" "B.Cu")
		(net "GND")
	)
	(via
		(at 216.460832 -439.905394)
		(size 0.508)
		(drill 0.254)
		(layers "F.Cu" "B.Cu")
		(net "GND")
	)
	(via
		(at 28.853638 -124.062236)
		(size 0.508)
		(drill 0.254)
		(layers "F.Cu" "B.Cu")
		(net "GND")
	)
	(via
		(at 72.791828 -160.212278)
		(size 0.508)
		(drill 0.254)
		(layers "F.Cu" "B.Cu")
		(net "GND")
	)
	(via
		(at 52.50688 -185.892948)
		(size 0.508)
		(drill 0.254)
		(layers "F.Cu" "B.Cu")
		(net "GND")
	)
	(via
		(at 349.27286 -407.638504)
		(size 0.4572)
		(drill 0.254)
		(layers "F.Cu" "B.Cu")
		(net "GND")
	)
	(via
		(at 175.355504 -111.775494)
		(size 0.4572)
		(drill 0.254)
		(layers "F.Cu" "B.Cu")
		(net "GND")
	)
	(via
		(at 41.310814 -262.76681)
		(size 0.4572)
		(drill 0.2032)
		(layers "F.Cu" "B.Cu")
		(net "GND")
	)
	(via
		(at 130.767074 -400.858228)
		(size 0.4064)
		(drill 0.2032)
		(layers "F.Cu" "B.Cu")
		(net "GND")
	)
	(via
		(at 30.547818 -337.235038)
		(size 0.508)
		(drill 0.254)
		(layers "F.Cu" "B.Cu")
		(net "GND")
	)
	(via
		(at 90.964766 -229.272846)
		(size 0.4572)
		(drill 0.2032)
		(layers "F.Cu" "B.Cu")
		(net "GND")
	)
	(via
		(at 337.604862 -267.755878)
		(size 0.4572)
		(drill 0.2032)
		(layers "F.Cu" "B.Cu")
		(net "GND")
	)
	(via
		(at 113.519966 -216.25052)
		(size 0.4572)
		(drill 0.2032)
		(layers "F.Cu" "B.Cu")
		(net "GND")
	)
	(via
		(at 455.011282 -271.266666)
		(size 0.4572)
		(drill 0.2032)
		(layers "F.Cu" "B.Cu")
		(net "GND")
	)
	(via
		(at 409.69692 -176.367948)
		(size 0.508)
		(drill 0.254)
		(layers "F.Cu" "B.Cu")
		(net "GND")
	)
	(via
		(at 307.782214 -265.316716)
		(size 0.4572)
		(drill 0.2032)
		(layers "F.Cu" "B.Cu")
		(net "GND")
	)
	(via
		(at 384.485388 -215.436704)
		(size 0.4572)
		(drill 0.2032)
		(layers "F.Cu" "B.Cu")
		(net "GND")
	)
	(via
		(at 375.667016 -266.941808)
		(size 0.4572)
		(drill 0.2032)
		(layers "F.Cu" "B.Cu")
		(net "GND")
	)
	(via
		(at 33.767014 -303.566576)
		(size 0.4572)
		(drill 0.2032)
		(layers "F.Cu" "B.Cu")
		(net "GND")
	)
	(via
		(at 175.91913 -424.398948)
		(size 0.508)
		(drill 0.254)
		(layers "F.Cu" "B.Cu")
		(net "GND")
	)
	(via
		(at 380.415038 -404.51786)
		(size 0.4572)
		(drill 0.254)
		(layers "F.Cu" "B.Cu")
		(net "GND")
	)
	(via
		(at 11.476228 -108.28274)
		(size 0.508)
		(drill 0.254)
		(layers "F.Cu" "B.Cu")
		(net "GND")
	)
	(via
		(at 130.66395 -124.234448)
		(size 0.508)
		(drill 0.254)
		(layers "F.Cu" "B.Cu")
		(net "GND")
	)
	(via
		(at 274.163282 -235.566712)
		(size 0.4572)
		(drill 0.2032)
		(layers "F.Cu" "B.Cu")
		(net "GND")
	)
	(via
		(at 123.497594 -282.405836)
		(size 0.4572)
		(drill 0.2032)
		(layers "F.Cu" "B.Cu")
		(net "GND")
	)
	(via
		(at 59.842146 -231.316784)
		(size 0.4572)
		(drill 0.2032)
		(layers "F.Cu" "B.Cu")
		(net "GND")
	)
	(via
		(at 147.165314 -403.883876)
		(size 0.4064)
		(drill 0.2032)
		(layers "F.Cu" "B.Cu")
		(net "GND")
	)
	(via
		(at 132.425694 -279.964134)
		(size 0.4572)
		(drill 0.2032)
		(layers "F.Cu" "B.Cu")
		(net "GND")
	)
	(via
		(at 308.506622 -42.916348)
		(size 0.508)
		(drill 0.254)
		(layers "F.Cu" "B.Cu")
		(net "GND")
	)
	(via
		(at 413.157924 -156.610304)
		(size 0.508)
		(drill 0.254)
		(layers "F.Cu" "B.Cu")
		(net "GND")
	)
	(via
		(at 153.652982 -400.224244)
		(size 0.4572)
		(drill 0.254)
		(layers "F.Cu" "B.Cu")
		(net "GND")
	)
	(via
		(at 395.431772 -16.967454)
		(size 0.508)
		(drill 0.254)
		(layers "F.Cu" "B.Cu")
		(net "GND")
	)
	(via
		(at 127.616966 -243.922804)
		(size 0.4572)
		(drill 0.2032)
		(layers "F.Cu" "B.Cu")
		(net "GND")
	)
	(via
		(at 378.376434 -216.25052)
		(size 0.4572)
		(drill 0.2032)
		(layers "F.Cu" "B.Cu")
		(net "GND")
	)
	(via
		(at 279.816814 -206.666592)
		(size 0.4572)
		(drill 0.2032)
		(layers "F.Cu" "B.Cu")
		(net "GND")
	)
	(via
		(at 376.136662 -287.28924)
		(size 0.4572)
		(drill 0.2032)
		(layers "F.Cu" "B.Cu")
		(net "GND")
	)
	(via
		(at 31.876746 -251.716794)
		(size 0.4572)
		(drill 0.2032)
		(layers "F.Cu" "B.Cu")
		(net "GND")
	)
	(via
		(at 71.79056 -54.381908)
		(size 0.508)
		(drill 0.254)
		(layers "F.Cu" "B.Cu")
		(net "GND")
	)
	(via
		(at 314.092082 -297.616626)
		(size 0.4572)
		(drill 0.2032)
		(layers "F.Cu" "B.Cu")
		(net "GND")
	)
	(via
		(at 170.462448 -416.550348)
		(size 0.508)
		(drill 0.254)
		(layers "F.Cu" "B.Cu")
		(net "GND")
	)
	(via
		(at 378.33681 -407.00452)
		(size 0.4064)
		(drill 0.2032)
		(layers "F.Cu" "B.Cu")
		(net "GND")
	)
	(via
		(at 344.25001 -438.651396)
		(size 0.4572)
		(drill 0.2032)
		(layers "F.Cu" "B.Cu")
		(net "GND")
	)
	(via
		(at 96.243394 -284.033722)
		(size 0.4572)
		(drill 0.2032)
		(layers "F.Cu" "B.Cu")
		(net "GND")
	)
	(via
		(at 378.956062 -280.778204)
		(size 0.4572)
		(drill 0.2032)
		(layers "F.Cu" "B.Cu")
		(net "GND")
	)
	(via
		(at 449.677282 -235.566712)
		(size 0.4572)
		(drill 0.2032)
		(layers "F.Cu" "B.Cu")
		(net "GND")
	)
	(via
		(at 124.327412 -243.108988)
		(size 0.4572)
		(drill 0.2032)
		(layers "F.Cu" "B.Cu")
		(net "GND")
	)
	(via
		(at 191.983614 -230.466646)
		(size 0.4572)
		(drill 0.2032)
		(layers "F.Cu" "B.Cu")
		(net "GND")
	)
	(via
		(at 58.824114 -272.966688)
		(size 0.4572)
		(drill 0.2032)
		(layers "F.Cu" "B.Cu")
		(net "GND")
	)
	(via
		(at 92.954348 -253.919736)
		(size 0.4572)
		(drill 0.2032)
		(layers "F.Cu" "B.Cu")
		(net "GND")
	)
	(via
		(at 13.345414 -241.516662)
		(size 0.4572)
		(drill 0.2032)
		(layers "F.Cu" "B.Cu")
		(net "GND")
	)
	(via
		(at 35.976814 -272.966688)
		(size 0.4572)
		(drill 0.2032)
		(layers "F.Cu" "B.Cu")
		(net "GND")
	)
	(via
		(at 66.367914 -238.116618)
		(size 0.4572)
		(drill 0.2032)
		(layers "F.Cu" "B.Cu")
		(net "GND")
	)
	(via
		(at 9.245346 -317.166752)
		(size 0.4572)
		(drill 0.2032)
		(layers "F.Cu" "B.Cu")
		(net "GND")
	)
	(via
		(at 370.38788 -238.225584)
		(size 0.4572)
		(drill 0.2032)
		(layers "F.Cu" "B.Cu")
		(net "GND")
	)
	(via
		(at 319.001648 -410.030168)
		(size 0.4064)
		(drill 0.2032)
		(layers "F.Cu" "B.Cu")
		(net "GND")
	)
	(via
		(at 216.824814 -215.166702)
		(size 0.4572)
		(drill 0.2032)
		(layers "F.Cu" "B.Cu")
		(net "GND")
	)
	(via
		(at 52.298346 -307.816758)
		(size 0.4572)
		(drill 0.2032)
		(layers "F.Cu" "B.Cu")
		(net "GND")
	)
	(via
		(at 126.317248 -264.50036)
		(size 0.4572)
		(drill 0.2032)
		(layers "F.Cu" "B.Cu")
		(net "GND")
	)
	(via
		(at 31.876746 -216.016586)
		(size 0.4572)
		(drill 0.2032)
		(layers "F.Cu" "B.Cu")
		(net "GND")
	)
	(via
		(at 276.373082 -297.616626)
		(size 0.4572)
		(drill 0.2032)
		(layers "F.Cu" "B.Cu")
		(net "GND")
	)
	(via
		(at 338.250022 -431.29962)
		(size 0.4572)
		(drill 0.2032)
		(layers "F.Cu" "B.Cu")
		(net "GND")
	)
	(via
		(at 45.179234 -108.047282)
		(size 0.508)
		(drill 0.254)
		(layers "F.Cu" "B.Cu")
		(net "GND")
	)
	(via
		(at 377.351798 -401.492212)
		(size 0.4572)
		(drill 0.254)
		(layers "F.Cu" "B.Cu")
		(net "GND")
	)
	(via
		(at 354.051616 -266.941808)
		(size 0.4572)
		(drill 0.2032)
		(layers "F.Cu" "B.Cu")
		(net "GND")
	)
	(via
		(at 157.708346 -273.816572)
		(size 0.4572)
		(drill 0.2032)
		(layers "F.Cu" "B.Cu")
		(net "GND")
	)
	(via
		(at 450.911214 -250.016772)
		(size 0.4572)
		(drill 0.2032)
		(layers "F.Cu" "B.Cu")
		(net "GND")
	)
	(via
		(at 342.250014 -434.899562)
		(size 0.4572)
		(drill 0.2032)
		(layers "F.Cu" "B.Cu")
		(net "GND")
	)
	(via
		(at 396.349982 -436.051198)
		(size 0.4572)
		(drill 0.2032)
		(layers "F.Cu" "B.Cu")
		(net "GND")
	)
	(via
		(at 76.971398 -403.883876)
		(size 0.4064)
		(drill 0.2032)
		(layers "F.Cu" "B.Cu")
		(net "GND")
	)
	(via
		(at 453.121014 -309.51678)
		(size 0.4572)
		(drill 0.2032)
		(layers "F.Cu" "B.Cu")
		(net "GND")
	)
	(via
		(at 194.193414 -275.516594)
		(size 0.4572)
		(drill 0.2032)
		(layers "F.Cu" "B.Cu")
		(net "GND")
	)
	(via
		(at 176.896014 -258.516628)
		(size 0.4572)
		(drill 0.2032)
		(layers "F.Cu" "B.Cu")
		(net "GND")
	)
	(via
		(at 20.889214 -228.766624)
		(size 0.4572)
		(drill 0.2032)
		(layers "F.Cu" "B.Cu")
		(net "GND")
	)
	(via
		(at 95.773748 -279.964134)
		(size 0.4572)
		(drill 0.2032)
		(layers "F.Cu" "B.Cu")
		(net "GND")
	)
	(via
		(at 51.064414 -233.86669)
		(size 0.4572)
		(drill 0.2032)
		(layers "F.Cu" "B.Cu")
		(net "GND")
	)
	(via
		(at 87.315294 -273.453098)
		(size 0.4318)
		(drill 0.2032)
		(layers "F.Cu" "B.Cu")
		(net "GND")
	)
	(via
		(at 39.420546 -313.766708)
		(size 0.4572)
		(drill 0.2032)
		(layers "F.Cu" "B.Cu")
		(net "GND")
	)
	(via
		(at 361.82808 -57.150508)
		(size 0.508)
		(drill 0.254)
		(layers "F.Cu" "B.Cu")
		(net "GND")
	)
	(via
		(at 442.133482 -297.616626)
		(size 0.4572)
		(drill 0.2032)
		(layers "F.Cu" "B.Cu")
		(net "GND")
	)
	(via
		(at 55.24754 -169.852848)
		(size 0.508)
		(drill 0.254)
		(layers "F.Cu" "B.Cu")
		(net "GND")
	)
	(via
		(at 390.349994 -438.651396)
		(size 0.4572)
		(drill 0.2032)
		(layers "F.Cu" "B.Cu")
		(net "GND")
	)
	(via
		(at 345.953334 -247.992138)
		(size 0.4572)
		(drill 0.2032)
		(layers "F.Cu" "B.Cu")
		(net "GND")
	)
	(via
		(at 223.050608 -222.69704)
		(size 0.508)
		(drill 0.254)
		(layers "F.Cu" "B.Cu")
		(net "GND")
	)
	(via
		(at 307.782214 -315.46673)
		(size 0.4572)
		(drill 0.2032)
		(layers "F.Cu" "B.Cu")
		(net "GND")
	)
	(via
		(at 262.60044 -101.803708)
		(size 0.508)
		(drill 0.254)
		(layers "F.Cu" "B.Cu")
		(net "GND")
	)
	(via
		(at 39.420546 -229.616762)
		(size 0.4572)
		(drill 0.2032)
		(layers "F.Cu" "B.Cu")
		(net "GND")
	)
	(via
		(at 309.908956 -400.224244)
		(size 0.4572)
		(drill 0.254)
		(layers "F.Cu" "B.Cu")
		(net "GND")
	)
	(via
		(at 115.039394 -274.266914)
		(size 0.4572)
		(drill 0.2032)
		(layers "F.Cu" "B.Cu")
		(net "GND")
	)
	(via
		(at 201.737214 -222.816674)
		(size 0.4572)
		(drill 0.2032)
		(layers "F.Cu" "B.Cu")
		(net "GND")
	)
	(via
		(at 405.648414 -268.71676)
		(size 0.4572)
		(drill 0.2032)
		(layers "F.Cu" "B.Cu")
		(net "GND")
	)
	(via
		(at 343.14638 -410.664152)
		(size 0.4572)
		(drill 0.254)
		(layers "F.Cu" "B.Cu")
		(net "GND")
	)
	(via
		(at 277.607014 -210.916774)
		(size 0.4572)
		(drill 0.2032)
		(layers "F.Cu" "B.Cu")
		(net "GND")
	)
	(via
		(at 46.964346 -221.96679)
		(size 0.4572)
		(drill 0.2032)
		(layers "F.Cu" "B.Cu")
		(net "GND")
	)
	(via
		(at 430.489614 -225.36658)
		(size 0.4572)
		(drill 0.2032)
		(layers "F.Cu" "B.Cu")
		(net "GND")
	)
	(via
		(at 161.54527 -310.366664)
		(size 0.4572)
		(drill 0.2032)
		(layers "F.Cu" "B.Cu")
		(net "GND")
	)
	(via
		(at 81.294478 -22.555962)
		(size 0.508)
		(drill 0.254)
		(layers "F.Cu" "B.Cu")
		(net "GND")
	)
	(via
		(at 93.369638 -400.858228)
		(size 0.4064)
		(drill 0.2032)
		(layers "F.Cu" "B.Cu")
		(net "GND")
	)
	(via
		(at 376.49912 -358.699308)
		(size 0.508)
		(drill 0.254)
		(layers "F.Cu" "B.Cu")
		(net "GND")
	)
	(via
		(at 11.135614 -286.56661)
		(size 0.4572)
		(drill 0.2032)
		(layers "F.Cu" "B.Cu")
		(net "GND")
	)
	(via
		(at 182.675276 -51.14671)
		(size 0.508)
		(drill 0.254)
		(layers "F.Cu" "B.Cu")
		(net "GND")
	)
	(via
		(at 112.580166 -219.506038)
		(size 0.4572)
		(drill 0.2032)
		(layers "F.Cu" "B.Cu")
		(net "GND")
	)
	(via
		(at 151.349964 -429.147224)
		(size 0.4572)
		(drill 0.2032)
		(layers "F.Cu" "B.Cu")
		(net "GND")
	)
	(via
		(at 424.836082 -310.366664)
		(size 0.4572)
		(drill 0.2032)
		(layers "F.Cu" "B.Cu")
		(net "GND")
	)
	(via
		(at 164.018214 -303.566576)
		(size 0.4572)
		(drill 0.2032)
		(layers "F.Cu" "B.Cu")
		(net "GND")
	)
	(via
		(at 413.192214 -301.866808)
		(size 0.4572)
		(drill 0.2032)
		(layers "F.Cu" "B.Cu")
		(net "GND")
	)
	(via
		(at 430.489614 -199.01662)
		(size 0.4572)
		(drill 0.2032)
		(layers "F.Cu" "B.Cu")
		(net "GND")
	)
	(via
		(at 127.726948 -262.058658)
		(size 0.4572)
		(drill 0.2032)
		(layers "F.Cu" "B.Cu")
		(net "GND")
	)
	(via
		(at 436.155846 -384.54203)
		(size 0.508)
		(drill 0.254)
		(layers "F.Cu" "B.Cu")
		(net "GND")
	)
	(via
		(at 425.705016 -134.89051)
		(size 0.508)
		(drill 0.254)
		(layers "F.Cu" "B.Cu")
		(net "GND")
	)
	(via
		(at 461.905096 -388.363714)
		(size 0.508)
		(drill 0.254)
		(layers "F.Cu" "B.Cu")
		(net "GND")
	)
	(via
		(at 443.367414 -290.816792)
		(size 0.4572)
		(drill 0.2032)
		(layers "F.Cu" "B.Cu")
		(net "GND")
	)
	(via
		(at 281.707082 -224.516696)
		(size 0.4572)
		(drill 0.2032)
		(layers "F.Cu" "B.Cu")
		(net "GND")
	)
	(via
		(at 93.27261 -406.34666)
		(size 0.4572)
		(drill 0.254)
		(layers "F.Cu" "B.Cu")
		(net "GND")
	)
	(via
		(at 361.929934 -223.575626)
		(size 0.4572)
		(drill 0.2032)
		(layers "F.Cu" "B.Cu")
		(net "GND")
	)
	(via
		(at 216.824814 -277.216616)
		(size 0.4572)
		(drill 0.2032)
		(layers "F.Cu" "B.Cu")
		(net "GND")
	)
	(via
		(at 202.971146 -223.666558)
		(size 0.4572)
		(drill 0.2032)
		(layers "F.Cu" "B.Cu")
		(net "GND")
	)
	(via
		(at 194.193414 -303.566576)
		(size 0.4572)
		(drill 0.2032)
		(layers "F.Cu" "B.Cu")
		(net "GND")
	)
	(via
		(at 254.45974 -422.3258)
		(size 0.508)
		(drill 0.254)
		(layers "F.Cu" "B.Cu")
		(net "GND")
	)
	(via
		(at 334.25003 -439.651394)
		(size 0.4572)
		(drill 0.2032)
		(layers "F.Cu" "B.Cu")
		(net "GND")
	)
	(via
		(at 115.979194 -267.755878)
		(size 0.4572)
		(drill 0.2032)
		(layers "F.Cu" "B.Cu")
		(net "GND")
	)
	(via
		(at 413.652462 -410.664152)
		(size 0.4572)
		(drill 0.254)
		(layers "F.Cu" "B.Cu")
		(net "GND")
	)
	(via
		(at 64.35725 -403.249892)
		(size 0.4572)
		(drill 0.254)
		(layers "F.Cu" "B.Cu")
		(net "GND")
	)
	(via
		(at 264.729214 -227.066602)
		(size 0.4572)
		(drill 0.2032)
		(layers "F.Cu" "B.Cu")
		(net "GND")
	)
	(via
		(at 294.374316 -368.369596)
		(size 0.508)
		(drill 0.254)
		(layers "F.Cu" "B.Cu")
		(net "GND")
	)
	(via
		(at 453.121014 -265.316716)
		(size 0.4572)
		(drill 0.2032)
		(layers "F.Cu" "B.Cu")
		(net "GND")
	)
	(via
		(at 167.461946 -307.816758)
		(size 0.4572)
		(drill 0.2032)
		(layers "F.Cu" "B.Cu")
		(net "GND")
	)
	(via
		(at 369.088416 -281.59202)
		(size 0.4572)
		(drill 0.2032)
		(layers "F.Cu" "B.Cu")
		(net "GND")
	)
	(via
		(at 457.221082 -305.266598)
		(size 0.4572)
		(drill 0.2032)
		(layers "F.Cu" "B.Cu")
		(net "GND")
	)
	(via
		(at 186.649614 -272.966688)
		(size 0.4572)
		(drill 0.2032)
		(layers "F.Cu" "B.Cu")
		(net "GND")
	)
	(via
		(at 171.562014 -305.266598)
		(size 0.4572)
		(drill 0.2032)
		(layers "F.Cu" "B.Cu")
		(net "GND")
	)
	(via
		(at 66.152014 -316.316614)
		(size 0.4572)
		(drill 0.2032)
		(layers "F.Cu" "B.Cu")
		(net "GND")
	)
	(via
		(at 132.785866 -213.732618)
		(size 0.4572)
		(drill 0.2032)
		(layers "F.Cu" "B.Cu")
		(net "GND")
	)
	(via
		(at 262.519414 -229.616762)
		(size 0.4572)
		(drill 0.2032)
		(layers "F.Cu" "B.Cu")
		(net "GND")
	)
	(via
		(at 9.245346 -217.716608)
		(size 0.4572)
		(drill 0.2032)
		(layers "F.Cu" "B.Cu")
		(net "GND")
	)
	(via
		(at 51.064414 -222.816674)
		(size 0.4572)
		(drill 0.2032)
		(layers "F.Cu" "B.Cu")
		(net "GND")
	)
	(via
		(at 210.514946 -263.616694)
		(size 0.4572)
		(drill 0.2032)
		(layers "F.Cu" "B.Cu")
		(net "GND")
	)
	(via
		(at 61.250068 -432.451256)
		(size 0.4572)
		(drill 0.2032)
		(layers "F.Cu" "B.Cu")
		(net "GND")
	)
	(via
		(at 207.071214 -194.766692)
		(size 0.4572)
		(drill 0.2032)
		(layers "F.Cu" "B.Cu")
		(net "GND")
	)
	(via
		(at 430.558448 -16.967454)
		(size 0.508)
		(drill 0.254)
		(layers "F.Cu" "B.Cu")
		(net "GND")
	)
	(via
		(at 367.568734 -221.94774)
		(size 0.4572)
		(drill 0.2032)
		(layers "F.Cu" "B.Cu")
		(net "GND")
	)
	(via
		(at 41.310814 -310.366664)
		(size 0.4572)
		(drill 0.2032)
		(layers "F.Cu" "B.Cu")
		(net "GND")
	)
	(via
		(at 17.622266 -19.13636)
		(size 0.508)
		(drill 0.254)
		(layers "F.Cu" "B.Cu")
		(net "GND")
	)
	(via
		(at 402.046948 -9.424924)
		(size 0.508)
		(drill 0.254)
		(layers "F.Cu" "B.Cu")
		(net "GND")
	)
	(via
		(at 171.562014 -277.216616)
		(size 0.4572)
		(drill 0.2032)
		(layers "F.Cu" "B.Cu")
		(net "GND")
	)
	(via
		(at 361.460034 -243.922804)
		(size 0.4572)
		(drill 0.2032)
		(layers "F.Cu" "B.Cu")
		(net "GND")
	)
	(via
		(at 409.748482 -210.066636)
		(size 0.4572)
		(drill 0.2032)
		(layers "F.Cu" "B.Cu")
		(net "GND")
	)
	(via
		(at 119.957342 -404.51786)
		(size 0.4572)
		(drill 0.254)
		(layers "F.Cu" "B.Cu")
		(net "GND")
	)
	(via
		(at 352.641662 -269.38351)
		(size 0.4572)
		(drill 0.2032)
		(layers "F.Cu" "B.Cu")
		(net "GND")
	)
	(via
		(at 26.512266 -16.978376)
		(size 0.508)
		(drill 0.254)
		(layers "F.Cu" "B.Cu")
		(net "GND")
	)
	(via
		(at 40.025828 -4.962652)
		(size 0.508)
		(drill 0.254)
		(layers "F.Cu" "B.Cu")
		(net "GND")
	)
	(via
		(at 159.918146 -208.366614)
		(size 0.4572)
		(drill 0.2032)
		(layers "F.Cu" "B.Cu")
		(net "GND")
	)
	(via
		(at 168.43883 -422.874948)
		(size 0.508)
		(drill 0.254)
		(layers "F.Cu" "B.Cu")
		(net "GND")
	)
	(via
		(at 447.81343 -73.581514)
		(size 0.508)
		(drill 0.254)
		(layers "F.Cu" "B.Cu")
		(net "GND")
	)
	(via
		(at 283.916882 -301.01667)
		(size 0.4572)
		(drill 0.2032)
		(layers "F.Cu" "B.Cu")
		(net "GND")
	)
	(via
		(at 172.795946 -287.416748)
		(size 0.4572)
		(drill 0.2032)
		(layers "F.Cu" "B.Cu")
		(net "GND")
	)
	(via
		(at 292.694614 -220.266768)
		(size 0.4572)
		(drill 0.2032)
		(layers "F.Cu" "B.Cu")
		(net "GND")
	)
	(via
		(at 387.22427 -190.223648)
		(size 0.508)
		(drill 0.254)
		(layers "F.Cu" "B.Cu")
		(net "GND")
	)
	(via
		(at 144.366234 -410.030168)
		(size 0.4064)
		(drill 0.2032)
		(layers "F.Cu" "B.Cu")
		(net "GND")
	)
	(via
		(at 457.221082 -264.466578)
		(size 0.4572)
		(drill 0.2032)
		(layers "F.Cu" "B.Cu")
		(net "GND")
	)
	(via
		(at 270.063214 -295.06672)
		(size 0.4572)
		(drill 0.2032)
		(layers "F.Cu" "B.Cu")
		(net "GND")
	)
	(via
		(at 368.618262 -271.011396)
		(size 0.4572)
		(drill 0.2032)
		(layers "F.Cu" "B.Cu")
		(net "GND")
	)
	(via
		(at 438.033414 -240.666778)
		(size 0.4572)
		(drill 0.2032)
		(layers "F.Cu" "B.Cu")
		(net "GND")
	)
	(via
		(at 199.527414 -232.166668)
		(size 0.4572)
		(drill 0.2032)
		(layers "F.Cu" "B.Cu")
		(net "GND")
	)
	(via
		(at 443.367414 -279.766776)
		(size 0.4572)
		(drill 0.2032)
		(layers "F.Cu" "B.Cu")
		(net "GND")
	)
	(via
		(at 52.298346 -317.166752)
		(size 0.4572)
		(drill 0.2032)
		(layers "F.Cu" "B.Cu")
		(net "GND")
	)
	(via
		(at 424.836082 -314.616592)
		(size 0.4572)
		(drill 0.2032)
		(layers "F.Cu" "B.Cu")
		(net "GND")
	)
	(via
		(at 216.824814 -249.166634)
		(size 0.4572)
		(drill 0.2032)
		(layers "F.Cu" "B.Cu")
		(net "GND")
	)
	(via
		(at 44.13377 -4.328668)
		(size 0.508)
		(drill 0.254)
		(layers "F.Cu" "B.Cu")
		(net "GND")
	)
	(via
		(at 121.708926 -123.112784)
		(size 0.508)
		(drill 0.254)
		(layers "F.Cu" "B.Cu")
		(net "GND")
	)
	(via
		(at 464.764882 -245.76659)
		(size 0.4572)
		(drill 0.2032)
		(layers "F.Cu" "B.Cu")
		(net "GND")
	)
	(via
		(at 147.526502 -401.492212)
		(size 0.4572)
		(drill 0.254)
		(layers "F.Cu" "B.Cu")
		(net "GND")
	)
	(via
		(at 304.338482 -250.866656)
		(size 0.4572)
		(drill 0.2032)
		(layers "F.Cu" "B.Cu")
		(net "GND")
	)
	(via
		(at 349.77324 -358.452674)
		(size 0.508)
		(drill 0.254)
		(layers "F.Cu" "B.Cu")
		(net "GND")
	)
	(via
		(at 128.287526 -335.187036)
		(size 0.49022)
		(drill 0.254)
		(layers "F.Cu" "B.Cu")
		(net "GND")
	)
	(via
		(at 69.250052 -439.651394)
		(size 0.4572)
		(drill 0.2032)
		(layers "F.Cu" "B.Cu")
		(net "GND")
	)
	(via
		(at 33.767014 -264.466578)
		(size 0.4572)
		(drill 0.2032)
		(layers "F.Cu" "B.Cu")
		(net "GND")
	)
	(via
		(at 467.535514 -88.76538)
		(size 0.508)
		(drill 0.254)
		(layers "F.Cu" "B.Cu")
		(net "GND")
	)
	(via
		(at 201.737214 -224.516696)
		(size 0.4572)
		(drill 0.2032)
		(layers "F.Cu" "B.Cu")
		(net "GND")
	)
	(via
		(at 110.305088 -297.19778)
		(size 0.508)
		(drill 0.254)
		(layers "F.Cu" "B.Cu")
		(net "GND")
	)
	(via
		(at 35.807396 -101.44379)
		(size 0.508)
		(drill 0.254)
		(layers "F.Cu" "B.Cu")
		(net "GND")
	)
	(via
		(at 128.26492 -25.845008)
		(size 0.508)
		(drill 0.254)
		(layers "F.Cu" "B.Cu")
		(net "GND")
	)
	(via
		(at 216.824814 -306.96662)
		(size 0.4572)
		(drill 0.2032)
		(layers "F.Cu" "B.Cu")
		(net "GND")
	)
	(via
		(at 358.640634 -226.017328)
		(size 0.4572)
		(drill 0.2032)
		(layers "F.Cu" "B.Cu")
		(net "GND")
	)
	(via
		(at 411.958282 -278.916638)
		(size 0.4572)
		(drill 0.2032)
		(layers "F.Cu" "B.Cu")
		(net "GND")
	)
	(via
		(at 157.708346 -298.466764)
		(size 0.4572)
		(drill 0.2032)
		(layers "F.Cu" "B.Cu")
		(net "GND")
	)
	(via
		(at 176.155604 -110.975394)
		(size 0.4572)
		(drill 0.254)
		(layers "F.Cu" "B.Cu")
		(net "GND")
	)
	(via
		(at 20.889214 -299.316648)
		(size 0.4572)
		(drill 0.2032)
		(layers "F.Cu" "B.Cu")
		(net "GND")
	)
	(via
		(at 40.063674 -354.109528)
		(size 0.49022)
		(drill 0.254)
		(layers "F.Cu" "B.Cu")
		(net "GND")
	)
	(via
		(at 132.315966 -234.15625)
		(size 0.4572)
		(drill 0.2032)
		(layers "F.Cu" "B.Cu")
		(net "GND")
	)
	(via
		(at 298.9326 -413.38754)
		(size 0.508)
		(drill 0.254)
		(layers "F.Cu" "B.Cu")
		(net "GND")
	)
	(via
		(at 384.485134 -233.34218)
		(size 0.4318)
		(drill 0.2032)
		(layers "F.Cu" "B.Cu")
		(net "GND")
	)
	(via
		(at 25.734518 -109.658658)
		(size 0.508)
		(drill 0.254)
		(layers "F.Cu" "B.Cu")
		(net "GND")
	)
	(via
		(at 201.737214 -249.166634)
		(size 0.4572)
		(drill 0.2032)
		(layers "F.Cu" "B.Cu")
		(net "GND")
	)
	(via
		(at 151.18588 -35.794188)
		(size 0.508)
		(drill 0.254)
		(layers "F.Cu" "B.Cu")
		(net "GND")
	)
	(via
		(at 385.534662 -282.405836)
		(size 0.4572)
		(drill 0.2032)
		(layers "F.Cu" "B.Cu")
		(net "GND")
	)
	(via
		(at 283.916882 -213.46668)
		(size 0.4572)
		(drill 0.2032)
		(layers "F.Cu" "B.Cu")
		(net "GND")
	)
	(via
		(at 445.577214 -278.066754)
		(size 0.4572)
		(drill 0.2032)
		(layers "F.Cu" "B.Cu")
		(net "GND")
	)
	(via
		(at 167.525954 -400.858228)
		(size 0.4064)
		(drill 0.2032)
		(layers "F.Cu" "B.Cu")
		(net "GND")
	)
	(via
		(at 20.889214 -295.916604)
		(size 0.4572)
		(drill 0.2032)
		(layers "F.Cu" "B.Cu")
		(net "GND")
	)
	(via
		(at 13.345414 -288.266632)
		(size 0.4572)
		(drill 0.2032)
		(layers "F.Cu" "B.Cu")
		(net "GND")
	)
	(via
		(at 91.074494 -266.941808)
		(size 0.4572)
		(drill 0.2032)
		(layers "F.Cu" "B.Cu")
		(net "GND")
	)
	(via
		(at 167.461946 -229.616762)
		(size 0.4572)
		(drill 0.2032)
		(layers "F.Cu" "B.Cu")
		(net "GND")
	)
	(via
		(at 318.64046 -406.370536)
		(size 0.4572)
		(drill 0.254)
		(layers "F.Cu" "B.Cu")
		(net "GND")
	)
	(via
		(at 415.402014 -289.11677)
		(size 0.4572)
		(drill 0.2032)
		(layers "F.Cu" "B.Cu")
		(net "GND")
	)
	(via
		(at 16.789146 -304.416714)
		(size 0.4572)
		(drill 0.2032)
		(layers "F.Cu" "B.Cu")
		(net "GND")
	)
	(via
		(at 122.659394 -403.883876)
		(size 0.4064)
		(drill 0.2032)
		(layers "F.Cu" "B.Cu")
		(net "GND")
	)
	(via
		(at 299.004482 -238.116618)
		(size 0.4572)
		(drill 0.2032)
		(layers "F.Cu" "B.Cu")
		(net "GND")
	)
	(via
		(at 86.37524 -275.08073)
		(size 0.4318)
		(drill 0.2032)
		(layers "F.Cu" "B.Cu")
		(net "GND")
	)
	(via
		(at 409.748482 -198.166736)
		(size 0.4572)
		(drill 0.2032)
		(layers "F.Cu" "B.Cu")
		(net "GND")
	)
	(via
		(at 20.889214 -232.166668)
		(size 0.4572)
		(drill 0.2032)
		(layers "F.Cu" "B.Cu")
		(net "GND")
	)
	(via
		(at 26.223214 -271.266666)
		(size 0.4572)
		(drill 0.2032)
		(layers "F.Cu" "B.Cu")
		(net "GND")
	)
	(via
		(at 216.824814 -216.866724)
		(size 0.4572)
		(drill 0.2032)
		(layers "F.Cu" "B.Cu")
		(net "GND")
	)
	(via
		(at 329.54722 -404.51786)
		(size 0.4572)
		(drill 0.254)
		(layers "F.Cu" "B.Cu")
		(net "GND")
	)
	(via
		(at 51.490118 -19.13636)
		(size 0.508)
		(drill 0.254)
		(layers "F.Cu" "B.Cu")
		(net "GND")
	)
	(via
		(at 120.952768 -248.32818)
		(size 0.4572)
		(drill 0.2032)
		(layers "F.Cu" "B.Cu")
		(net "GND")
	)
	(via
		(at 176.896014 -247.466612)
		(size 0.4572)
		(drill 0.2032)
		(layers "F.Cu" "B.Cu")
		(net "GND")
	)
	(via
		(at 18.484596 -393.615926)
		(size 0.508)
		(drill 0.254)
		(layers "F.Cu" "B.Cu")
		(net "GND")
	)
	(via
		(at 301.684944 -360.778298)
		(size 0.508)
		(drill 0.254)
		(layers "F.Cu" "B.Cu")
		(net "GND")
	)
	(via
		(at 304.338482 -310.366664)
		(size 0.4572)
		(drill 0.2032)
		(layers "F.Cu" "B.Cu")
		(net "GND")
	)
	(via
		(at 9.492234 -12.544552)
		(size 0.508)
		(drill 0.254)
		(layers "F.Cu" "B.Cu")
		(net "GND")
	)
	(via
		(at 100.472748 -279.964134)
		(size 0.4572)
		(drill 0.2032)
		(layers "F.Cu" "B.Cu")
		(net "GND")
	)
	(via
		(at 209.281014 -308.666642)
		(size 0.4572)
		(drill 0.2032)
		(layers "F.Cu" "B.Cu")
		(net "GND")
	)
	(via
		(at 453.121014 -283.166566)
		(size 0.4572)
		(drill 0.2032)
		(layers "F.Cu" "B.Cu")
		(net "GND")
	)
	(via
		(at 413.996886 -182.999126)
		(size 0.508)
		(drill 0.254)
		(layers "F.Cu" "B.Cu")
		(net "GND")
	)
	(via
		(at 46.964346 -289.11677)
		(size 0.4572)
		(drill 0.2032)
		(layers "F.Cu" "B.Cu")
		(net "GND")
	)
	(via
		(at 429.813466 -6.586474)
		(size 0.508)
		(drill 0.254)
		(layers "F.Cu" "B.Cu")
		(net "GND")
	)
	(via
		(at 28.433014 -232.166668)
		(size 0.4572)
		(drill 0.2032)
		(layers "F.Cu" "B.Cu")
		(net "GND")
	)
	(via
		(at 86.301326 -330.166472)
		(size 0.508)
		(drill 0.254)
		(layers "F.Cu" "B.Cu")
		(net "GND")
	)
	(via
		(at 405.648414 -223.666558)
		(size 0.4572)
		(drill 0.2032)
		(layers "F.Cu" "B.Cu")
		(net "GND")
	)
	(via
		(at 417.05403 -207.51673)
		(size 0.4572)
		(drill 0.2032)
		(layers "F.Cu" "B.Cu")
		(net "GND")
	)
	(via
		(at 2.764536 -391.590022)
		(size 0.508)
		(drill 0.254)
		(layers "F.Cu" "B.Cu")
		(net "GND")
	)
	(via
		(at 345.593162 -276.708616)
		(size 0.4572)
		(drill 0.2032)
		(layers "F.Cu" "B.Cu")
		(net "GND")
	)
	(via
		(at 135.135366 -226.017328)
		(size 0.4572)
		(drill 0.2032)
		(layers "F.Cu" "B.Cu")
		(net "GND")
	)
	(via
		(at 302.04029 -354.972366)
		(size 0.508)
		(drill 0.254)
		(layers "F.Cu" "B.Cu")
		(net "GND")
	)
	(via
		(at 336.250026 -425.547282)
		(size 0.4572)
		(drill 0.2032)
		(layers "F.Cu" "B.Cu")
		(net "GND")
	)
	(via
		(at 405.648414 -301.866808)
		(size 0.4572)
		(drill 0.2032)
		(layers "F.Cu" "B.Cu")
		(net "GND")
	)
	(via
		(at 315.938408 -410.030168)
		(size 0.4064)
		(drill 0.2032)
		(layers "F.Cu" "B.Cu")
		(net "GND")
	)
	(via
		(at 378.84608 -236.597952)
		(size 0.4572)
		(drill 0.2032)
		(layers "F.Cu" "B.Cu")
		(net "GND")
	)
	(via
		(at 104.231948 -278.336502)
		(size 0.4572)
		(drill 0.2032)
		(layers "F.Cu" "B.Cu")
		(net "GND")
	)
	(via
		(at 295.077896 -361.494324)
		(size 0.508)
		(drill 0.254)
		(layers "F.Cu" "B.Cu")
		(net "GND")
	)
	(via
		(at 147.526502 -400.224244)
		(size 0.4572)
		(drill 0.254)
		(layers "F.Cu" "B.Cu")
		(net "GND")
	)
	(via
		(at 458.455014 -225.36658)
		(size 0.4572)
		(drill 0.2032)
		(layers "F.Cu" "B.Cu")
		(net "GND")
	)
	(via
		(at 85.905594 -264.50036)
		(size 0.4318)
		(drill 0.2032)
		(layers "F.Cu" "B.Cu")
		(net "GND")
	)
	(via
		(at 120.777 -54.02199)
		(size 0.508)
		(drill 0.254)
		(layers "F.Cu" "B.Cu")
		(net "GND")
	)
	(via
		(at 429.764952 -390.855962)
		(size 0.508)
		(drill 0.254)
		(layers "F.Cu" "B.Cu")
		(net "GND")
	)
	(via
		(at 402.046948 -7.215124)
		(size 0.508)
		(drill 0.254)
		(layers "F.Cu" "B.Cu")
		(net "GND")
	)
	(via
		(at 264.729214 -220.266768)
		(size 0.4572)
		(drill 0.2032)
		(layers "F.Cu" "B.Cu")
		(net "GND")
	)
	(via
		(at 348.772734 -213.732618)
		(size 0.4572)
		(drill 0.2032)
		(layers "F.Cu" "B.Cu")
		(net "GND")
	)
	(via
		(at 134.349998 -438.651396)
		(size 0.4572)
		(drill 0.2032)
		(layers "F.Cu" "B.Cu")
		(net "GND")
	)
	(via
		(at 300.238414 -270.416782)
		(size 0.4572)
		(drill 0.2032)
		(layers "F.Cu" "B.Cu")
		(net "GND")
	)
	(via
		(at 94.723712 -243.922804)
		(size 0.4572)
		(drill 0.2032)
		(layers "F.Cu" "B.Cu")
		(net "GND")
	)
	(via
		(at 91.904566 -222.761556)
		(size 0.4572)
		(drill 0.2032)
		(layers "F.Cu" "B.Cu")
		(net "GND")
	)
	(via
		(at 171.50588 -127.974598)
		(size 0.508)
		(drill 0.254)
		(layers "F.Cu" "B.Cu")
		(net "GND")
	)
	(via
		(at 210.514946 -203.266802)
		(size 0.4572)
		(drill 0.2032)
		(layers "F.Cu" "B.Cu")
		(net "GND")
	)
	(via
		(at 190.093346 -309.51678)
		(size 0.4572)
		(drill 0.2032)
		(layers "F.Cu" "B.Cu")
		(net "GND")
	)
	(via
		(at 136.349994 -437.34736)
		(size 0.4572)
		(drill 0.2032)
		(layers "F.Cu" "B.Cu")
		(net "GND")
	)
	(via
		(at 195.427346 -227.066602)
		(size 0.4572)
		(drill 0.2032)
		(layers "F.Cu" "B.Cu")
		(net "GND")
	)
	(via
		(at 87.205566 -245.55069)
		(size 0.4318)
		(drill 0.2032)
		(layers "F.Cu" "B.Cu")
		(net "GND")
	)
	(via
		(at 307.782214 -251.716794)
		(size 0.4572)
		(drill 0.2032)
		(layers "F.Cu" "B.Cu")
		(net "GND")
	)
	(via
		(at 259.075682 -250.866656)
		(size 0.4572)
		(drill 0.2032)
		(layers "F.Cu" "B.Cu")
		(net "GND")
	)
	(via
		(at 311.255156 -407.638504)
		(size 0.4572)
		(drill 0.254)
		(layers "F.Cu" "B.Cu")
		(net "GND")
	)
	(via
		(at 106.941366 -226.017328)
		(size 0.4572)
		(drill 0.2032)
		(layers "F.Cu" "B.Cu")
		(net "GND")
	)
	(via
		(at 457.221082 -245.76659)
		(size 0.4572)
		(drill 0.2032)
		(layers "F.Cu" "B.Cu")
		(net "GND")
	)
	(via
		(at 424.999404 -354.180394)
		(size 0.508)
		(drill 0.254)
		(layers "F.Cu" "B.Cu")
		(net "GND")
	)
	(via
		(at 339.330538 -73.85177)
		(size 0.508)
		(drill 0.254)
		(layers "F.Cu" "B.Cu")
		(net "GND")
	)
	(via
		(at 41.310814 -278.916638)
		(size 0.4572)
		(drill 0.2032)
		(layers "F.Cu" "B.Cu")
		(net "GND")
	)
	(via
		(at 154.911806 -400.224244)
		(size 0.4572)
		(drill 0.254)
		(layers "F.Cu" "B.Cu")
		(net "GND")
	)
	(via
		(at 336.085434 -235.783882)
		(size 0.4572)
		(drill 0.2032)
		(layers "F.Cu" "B.Cu")
		(net "GND")
	)
	(via
		(at 266.619482 -235.566712)
		(size 0.4572)
		(drill 0.2032)
		(layers "F.Cu" "B.Cu")
		(net "GND")
	)
	(via
		(at 304.338482 -264.466578)
		(size 0.4572)
		(drill 0.2032)
		(layers "F.Cu" "B.Cu")
		(net "GND")
	)
	(via
		(at 299.004482 -205.816708)
		(size 0.4572)
		(drill 0.2032)
		(layers "F.Cu" "B.Cu")
		(net "GND")
	)
	(via
		(at 413.652462 -409.396184)
		(size 0.4572)
		(drill 0.254)
		(layers "F.Cu" "B.Cu")
		(net "GND")
	)
	(via
		(at 25.48255 -4.328668)
		(size 0.508)
		(drill 0.254)
		(layers "F.Cu" "B.Cu")
		(net "GND")
	)
	(via
		(at 11.135614 -213.46668)
		(size 0.4572)
		(drill 0.2032)
		(layers "F.Cu" "B.Cu")
		(net "GND")
	)
	(via
		(at 340.305136 -333.833724)
		(size 0.508)
		(drill 0.254)
		(layers "F.Cu" "B.Cu")
		(net "GND")
	)
	(via
		(at 98.013012 -246.364506)
		(size 0.4572)
		(drill 0.2032)
		(layers "F.Cu" "B.Cu")
		(net "GND")
	)
	(via
		(at 443.367414 -210.916774)
		(size 0.4572)
		(drill 0.2032)
		(layers "F.Cu" "B.Cu")
		(net "GND")
	)
	(via
		(at 52.298346 -244.916706)
		(size 0.4572)
		(drill 0.2032)
		(layers "F.Cu" "B.Cu")
		(net "GND")
	)
	(via
		(at 411.958282 -308.666642)
		(size 0.4572)
		(drill 0.2032)
		(layers "F.Cu" "B.Cu")
		(net "GND")
	)
	(via
		(at 18.679414 -235.566712)
		(size 0.4572)
		(drill 0.2032)
		(layers "F.Cu" "B.Cu")
		(net "GND")
	)
	(via
		(at 199.527414 -286.56661)
		(size 0.4572)
		(drill 0.2032)
		(layers "F.Cu" "B.Cu")
		(net "GND")
	)
	(via
		(at 18.230088 -107.123484)
		(size 0.508)
		(drill 0.254)
		(layers "F.Cu" "B.Cu")
		(net "GND")
	)
	(via
		(at 291.460682 -316.316614)
		(size 0.4572)
		(drill 0.2032)
		(layers "F.Cu" "B.Cu")
		(net "GND")
	)
	(via
		(at 210.64728 -75.377548)
		(size 0.508)
		(drill 0.254)
		(layers "F.Cu" "B.Cu")
		(net "GND")
	)
	(via
		(at 384.015234 -221.133924)
		(size 0.4572)
		(drill 0.2032)
		(layers "F.Cu" "B.Cu")
		(net "GND")
	)
	(via
		(at 103.618792 -297.077638)
		(size 0.508)
		(drill 0.254)
		(layers "F.Cu" "B.Cu")
		(net "GND")
	)
	(via
		(at 334.053688 -400.858228)
		(size 0.4064)
		(drill 0.2032)
		(layers "F.Cu" "B.Cu")
		(net "GND")
	)
	(via
		(at 56.398414 -301.01667)
		(size 0.4572)
		(drill 0.2032)
		(layers "F.Cu" "B.Cu")
		(net "GND")
	)
	(via
		(at 279.816814 -214.316564)
		(size 0.4572)
		(drill 0.2032)
		(layers "F.Cu" "B.Cu")
		(net "GND")
	)
	(via
		(at 198.12508 -111.324898)
		(size 0.508)
		(drill 0.254)
		(layers "F.Cu" "B.Cu")
		(net "GND")
	)
	(via
		(at 460.664814 -210.916774)
		(size 0.4572)
		(drill 0.2032)
		(layers "F.Cu" "B.Cu")
		(net "GND")
	)
	(via
		(at 37.210746 -240.666778)
		(size 0.4572)
		(drill 0.2032)
		(layers "F.Cu" "B.Cu")
		(net "GND")
	)
	(via
		(at 445.360552 -7.20344)
		(size 0.508)
		(drill 0.254)
		(layers "F.Cu" "B.Cu")
		(net "GND")
	)
	(via
		(at 135.605266 -231.714548)
		(size 0.4572)
		(drill 0.2032)
		(layers "F.Cu" "B.Cu")
		(net "GND")
	)
	(via
		(at 311.666382 -210.066636)
		(size 0.4572)
		(drill 0.2032)
		(layers "F.Cu" "B.Cu")
		(net "GND")
	)
	(via
		(at 374.726962 -279.964134)
		(size 0.4572)
		(drill 0.2032)
		(layers "F.Cu" "B.Cu")
		(net "GND")
	)
	(via
		(at 362.979462 -274.266914)
		(size 0.4572)
		(drill 0.2032)
		(layers "F.Cu" "B.Cu")
		(net "GND")
	)
	(via
		(at 356.620064 -237.863126)
		(size 0.4572)
		(drill 0.2032)
		(layers "F.Cu" "B.Cu")
		(net "GND")
	)
	(via
		(at 90.964512 -226.017328)
		(size 0.4572)
		(drill 0.2032)
		(layers "F.Cu" "B.Cu")
		(net "GND")
	)
	(via
		(at 33.767014 -200.716642)
		(size 0.4572)
		(drill 0.2032)
		(layers "F.Cu" "B.Cu")
		(net "GND")
	)
	(via
		(at 296.794682 -204.116686)
		(size 0.4572)
		(drill 0.2032)
		(layers "F.Cu" "B.Cu")
		(net "GND")
	)
	(via
		(at 285.150814 -231.316784)
		(size 0.4572)
		(drill 0.2032)
		(layers "F.Cu" "B.Cu")
		(net "GND")
	)
	(via
		(at 270.063214 -261.916672)
		(size 0.4572)
		(drill 0.2032)
		(layers "F.Cu" "B.Cu")
		(net "GND")
	)
	(via
		(at 216.824814 -211.766658)
		(size 0.4572)
		(drill 0.2032)
		(layers "F.Cu" "B.Cu")
		(net "GND")
	)
	(via
		(at 413.01797 -311.216802)
		(size 0.4572)
		(drill 0.2032)
		(layers "F.Cu" "B.Cu")
		(net "GND")
	)
	(via
		(at 374.147334 -247.992138)
		(size 0.4572)
		(drill 0.2032)
		(layers "F.Cu" "B.Cu")
		(net "GND")
	)
	(via
		(at 89.555066 -223.575626)
		(size 0.4572)
		(drill 0.2032)
		(layers "F.Cu" "B.Cu")
		(net "GND")
	)
	(via
		(at 157.708346 -263.616694)
		(size 0.4572)
		(drill 0.2032)
		(layers "F.Cu" "B.Cu")
		(net "GND")
	)
	(via
		(at 333.8703 -81.239614)
		(size 0.508)
		(drill 0.254)
		(layers "F.Cu" "B.Cu")
		(net "GND")
	)
	(via
		(at 283.916882 -202.416664)
		(size 0.4572)
		(drill 0.2032)
		(layers "F.Cu" "B.Cu")
		(net "GND")
	)
	(via
		(at 346.532962 -289.807142)
		(size 0.4572)
		(drill 0.2032)
		(layers "F.Cu" "B.Cu")
		(net "GND")
	)
	(via
		(at 445.577214 -268.71676)
		(size 0.4572)
		(drill 0.2032)
		(layers "F.Cu" "B.Cu")
		(net "GND")
	)
	(via
		(at 319.686686 -12.544552)
		(size 0.508)
		(drill 0.254)
		(layers "F.Cu" "B.Cu")
		(net "GND")
	)
	(via
		(at 81.477866 -401.492212)
		(size 0.4572)
		(drill 0.254)
		(layers "F.Cu" "B.Cu")
		(net "GND")
	)
	(via
		(at 422.945814 -251.716794)
		(size 0.4572)
		(drill 0.2032)
		(layers "F.Cu" "B.Cu")
		(net "GND")
	)
	(via
		(at 126.953772 -351.796858)
		(size 0.508)
		(drill 0.254)
		(layers "F.Cu" "B.Cu")
		(net "GND")
	)
	(via
		(at 55.260494 -164.472874)
		(size 0.49022)
		(drill 0.254)
		(layers "F.Cu" "B.Cu")
		(net "GND")
	)
	(via
		(at 115.716304 -359.94975)
		(size 0.508)
		(drill 0.254)
		(layers "F.Cu" "B.Cu")
		(net "GND")
	)
	(via
		(at 368.916204 -254.94615)
		(size 0.4572)
		(drill 0.2032)
		(layers "F.Cu" "B.Cu")
		(net "GND")
	)
	(via
		(at 108.820966 -234.15625)
		(size 0.4572)
		(drill 0.2032)
		(layers "F.Cu" "B.Cu")
		(net "GND")
	)
	(via
		(at 384.485134 -225.203258)
		(size 0.4572)
		(drill 0.2032)
		(layers "F.Cu" "B.Cu")
		(net "GND")
	)
	(via
		(at 210.514946 -270.416782)
		(size 0.4572)
		(drill 0.2032)
		(layers "F.Cu" "B.Cu")
		(net "GND")
	)
	(via
		(at 214.615014 -264.466578)
		(size 0.4572)
		(drill 0.2032)
		(layers "F.Cu" "B.Cu")
		(net "GND")
	)
	(via
		(at 378.84608 -238.225584)
		(size 0.4572)
		(drill 0.2032)
		(layers "F.Cu" "B.Cu")
		(net "GND")
	)
	(via
		(at 117.279166 -222.761556)
		(size 0.4572)
		(drill 0.2032)
		(layers "F.Cu" "B.Cu")
		(net "GND")
	)
	(via
		(at 410.68625 -400.858228)
		(size 0.4064)
		(drill 0.2032)
		(layers "F.Cu" "B.Cu")
		(net "GND")
	)
	(via
		(at 81.305654 -340.977728)
		(size 0.49022)
		(drill 0.254)
		(layers "F.Cu" "B.Cu")
		(net "GND")
	)
	(via
		(at 383.478278 -403.249892)
		(size 0.4572)
		(drill 0.254)
		(layers "F.Cu" "B.Cu")
		(net "GND")
	)
	(via
		(at 346.20962 -406.370536)
		(size 0.4572)
		(drill 0.254)
		(layers "F.Cu" "B.Cu")
		(net "GND")
	)
	(via
		(at 212.724746 -276.366732)
		(size 0.4572)
		(drill 0.2032)
		(layers "F.Cu" "B.Cu")
		(net "GND")
	)
	(via
		(at 190.093346 -204.96657)
		(size 0.4572)
		(drill 0.2032)
		(layers "F.Cu" "B.Cu")
		(net "GND")
	)
	(via
		(at 414.070292 -181.470554)
		(size 0.49022)
		(drill 0.254)
		(layers "F.Cu" "B.Cu")
		(net "GND")
	)
	(via
		(at 49.04105 -400.224244)
		(size 0.4572)
		(drill 0.254)
		(layers "F.Cu" "B.Cu")
		(net "GND")
	)
	(via
		(at 341.105744 -40.462454)
		(size 0.4572)
		(drill 0.2032)
		(layers "F.Cu" "B.Cu")
		(net "GND")
	)
	(via
		(at 191.676782 -26.743152)
		(size 0.508)
		(drill 0.254)
		(layers "F.Cu" "B.Cu")
		(net "GND")
	)
	(via
		(at 387.884162 -262.058404)
		(size 0.4572)
		(drill 0.2032)
		(layers "F.Cu" "B.Cu")
		(net "GND")
	)
	(via
		(at 379.426216 -281.59202)
		(size 0.4572)
		(drill 0.2032)
		(layers "F.Cu" "B.Cu")
		(net "GND")
	)
	(via
		(at 270.063214 -301.866808)
		(size 0.4572)
		(drill 0.2032)
		(layers "F.Cu" "B.Cu")
		(net "GND")
	)
	(via
		(at 348.882716 -271.011396)
		(size 0.4572)
		(drill 0.2032)
		(layers "F.Cu" "B.Cu")
		(net "GND")
	)
	(via
		(at 190.093346 -223.666558)
		(size 0.4572)
		(drill 0.2032)
		(layers "F.Cu" "B.Cu")
		(net "GND")
	)
	(via
		(at 376.073416 -337.692238)
		(size 0.49022)
		(drill 0.254)
		(layers "F.Cu" "B.Cu")
		(net "GND")
	)
	(via
		(at 386.364734 -218.692222)
		(size 0.4572)
		(drill 0.2032)
		(layers "F.Cu" "B.Cu")
		(net "GND")
	)
	(via
		(at 176.896014 -196.466714)
		(size 0.4572)
		(drill 0.2032)
		(layers "F.Cu" "B.Cu")
		(net "GND")
	)
	(via
		(at 394.585444 -6.07949)
		(size 0.508)
		(drill 0.254)
		(layers "F.Cu" "B.Cu")
		(net "GND")
	)
	(via
		(at 407.525982 -407.638504)
		(size 0.4572)
		(drill 0.254)
		(layers "F.Cu" "B.Cu")
		(net "GND")
	)
	(via
		(at 429.733964 -441.225432)
		(size 0.508)
		(drill 0.254)
		(layers "F.Cu" "B.Cu")
		(net "GND")
	)
	(via
		(at 48.508158 -170.108372)
		(size 0.508)
		(drill 0.254)
		(layers "F.Cu" "B.Cu")
		(net "GND")
	)
	(via
		(at 66.152014 -280.61666)
		(size 0.4572)
		(drill 0.2032)
		(layers "F.Cu" "B.Cu")
		(net "GND")
	)
	(via
		(at 389.146542 -406.370536)
		(size 0.4572)
		(drill 0.254)
		(layers "F.Cu" "B.Cu")
		(net "GND")
	)
	(via
		(at 115.652804 -132.178806)
		(size 0.508)
		(drill 0.254)
		(layers "F.Cu" "B.Cu")
		(net "GND")
	)
	(via
		(at 291.460682 -213.46668)
		(size 0.4572)
		(drill 0.2032)
		(layers "F.Cu" "B.Cu")
		(net "GND")
	)
	(via
		(at 117.823996 -242.96116)
		(size 0.4572)
		(drill 0.2032)
		(layers "F.Cu" "B.Cu")
		(net "GND")
	)
	(via
		(at 37.210746 -248.31675)
		(size 0.4572)
		(drill 0.2032)
		(layers "F.Cu" "B.Cu")
		(net "GND")
	)
	(via
		(at 421.89146 -360.074972)
		(size 0.508)
		(drill 0.254)
		(layers "F.Cu" "B.Cu")
		(net "GND")
	)
	(via
		(at 39.420546 -220.266768)
		(size 0.4572)
		(drill 0.2032)
		(layers "F.Cu" "B.Cu")
		(net "GND")
	)
	(via
		(at 264.729214 -281.466798)
		(size 0.4572)
		(drill 0.2032)
		(layers "F.Cu" "B.Cu")
		(net "GND")
	)
	(via
		(at 179.105814 -289.966654)
		(size 0.4572)
		(drill 0.2032)
		(layers "F.Cu" "B.Cu")
		(net "GND")
	)
	(via
		(at 184.439814 -291.666676)
		(size 0.4572)
		(drill 0.2032)
		(layers "F.Cu" "B.Cu")
		(net "GND")
	)
	(via
		(at 161.038286 -401.492212)
		(size 0.4572)
		(drill 0.254)
		(layers "F.Cu" "B.Cu")
		(net "GND")
	)
	(via
		(at 358.71658 -58.661808)
		(size 0.508)
		(drill 0.254)
		(layers "F.Cu" "B.Cu")
		(net "GND")
	)
	(via
		(at 97.342706 -326.790812)
		(size 0.508)
		(drill 0.254)
		(layers "F.Cu" "B.Cu")
		(net "GND")
	)
	(via
		(at 299.004482 -213.46668)
		(size 0.4572)
		(drill 0.2032)
		(layers "F.Cu" "B.Cu")
		(net "GND")
	)
	(via
		(at 405.93137 -5.585714)
		(size 0.508)
		(drill 0.254)
		(layers "F.Cu" "B.Cu")
		(net "GND")
	)
	(via
		(at 44.754546 -306.116736)
		(size 0.4572)
		(drill 0.2032)
		(layers "F.Cu" "B.Cu")
		(net "GND")
	)
	(via
		(at 356.761034 -232.528364)
		(size 0.4572)
		(drill 0.2032)
		(layers "F.Cu" "B.Cu")
		(net "GND")
	)
	(via
		(at 306.0192 -27.6606)
		(size 0.508)
		(drill 0.254)
		(layers "F.Cu" "B.Cu")
		(net "GND")
	)
	(via
		(at 41.308274 -354.109528)
		(size 0.49022)
		(drill 0.254)
		(layers "F.Cu" "B.Cu")
		(net "GND")
	)
	(via
		(at 455.011282 -297.616626)
		(size 0.4572)
		(drill 0.2032)
		(layers "F.Cu" "B.Cu")
		(net "GND")
	)
	(via
		(at 103.80599 -331.776832)
		(size 0.49022)
		(drill 0.254)
		(layers "F.Cu" "B.Cu")
		(net "GND")
	)
	(via
		(at 360.98988 -215.436704)
		(size 0.4572)
		(drill 0.2032)
		(layers "F.Cu" "B.Cu")
		(net "GND")
	)
	(via
		(at 94.833694 -258.80314)
		(size 0.4572)
		(drill 0.2032)
		(layers "F.Cu" "B.Cu")
		(net "GND")
	)
	(via
		(at 414.85947 -181.470554)
		(size 0.49022)
		(drill 0.254)
		(layers "F.Cu" "B.Cu")
		(net "GND")
	)
	(via
		(at 464.764882 -299.316648)
		(size 0.4572)
		(drill 0.2032)
		(layers "F.Cu" "B.Cu")
		(net "GND")
	)
	(via
		(at 124.797566 -216.25052)
		(size 0.4572)
		(drill 0.2032)
		(layers "F.Cu" "B.Cu")
		(net "GND")
	)
	(via
		(at 281.707082 -211.766658)
		(size 0.4572)
		(drill 0.2032)
		(layers "F.Cu" "B.Cu")
		(net "GND")
	)
	(via
		(at 424.88358 -147.450048)
		(size 0.508)
		(drill 0.254)
		(layers "F.Cu" "B.Cu")
		(net "GND")
	)
	(via
		(at 127.147066 -217.064336)
		(size 0.4572)
		(drill 0.2032)
		(layers "F.Cu" "B.Cu")
		(net "GND")
	)
	(via
		(at 190.093346 -225.36658)
		(size 0.4572)
		(drill 0.2032)
		(layers "F.Cu" "B.Cu")
		(net "GND")
	)
	(via
		(at 88.145366 -335.187036)
		(size 0.49022)
		(drill 0.254)
		(layers "F.Cu" "B.Cu")
		(net "GND")
	)
	(via
		(at 14.579346 -246.616728)
		(size 0.4572)
		(drill 0.2032)
		(layers "F.Cu" "B.Cu")
		(net "GND")
	)
	(via
		(at 91.434666 -228.45903)
		(size 0.4572)
		(drill 0.2032)
		(layers "F.Cu" "B.Cu")
		(net "GND")
	)
	(via
		(at 306.548282 -215.166702)
		(size 0.4572)
		(drill 0.2032)
		(layers "F.Cu" "B.Cu")
		(net "GND")
	)
	(via
		(at 434.589682 -314.616592)
		(size 0.4572)
		(drill 0.2032)
		(layers "F.Cu" "B.Cu")
		(net "GND")
	)
	(via
		(at 55.151782 -351.54997)
		(size 0.508)
		(drill 0.254)
		(layers "F.Cu" "B.Cu")
		(net "GND")
	)
	(via
		(at 48.82388 -104.689148)
		(size 0.508)
		(drill 0.254)
		(layers "F.Cu" "B.Cu")
		(net "GND")
	)
	(via
		(at 135.273542 -400.224244)
		(size 0.4572)
		(drill 0.254)
		(layers "F.Cu" "B.Cu")
		(net "GND")
	)
	(via
		(at 423.182796 -58.34634)
		(size 0.508)
		(drill 0.254)
		(layers "F.Cu" "B.Cu")
		(net "GND")
	)
	(via
		(at 182.549546 -225.36658)
		(size 0.4572)
		(drill 0.2032)
		(layers "F.Cu" "B.Cu")
		(net "GND")
	)
	(via
		(at 332.28788 -77.282548)
		(size 0.508)
		(drill 0.254)
		(layers "F.Cu" "B.Cu")
		(net "GND")
	)
	(via
		(at 171.783248 -358.534716)
		(size 0.508)
		(drill 0.254)
		(layers "F.Cu" "B.Cu")
		(net "GND")
	)
	(via
		(at 21.882608 -5.596636)
		(size 0.508)
		(drill 0.254)
		(layers "F.Cu" "B.Cu")
		(net "GND")
	)
	(via
		(at 268.829282 -312.91657)
		(size 0.4572)
		(drill 0.2032)
		(layers "F.Cu" "B.Cu")
		(net "GND")
	)
	(via
		(at 347.363034 -247.178322)
		(size 0.4572)
		(drill 0.2032)
		(layers "F.Cu" "B.Cu")
		(net "GND")
	)
	(via
		(at 413.192214 -240.666778)
		(size 0.4572)
		(drill 0.2032)
		(layers "F.Cu" "B.Cu")
		(net "GND")
	)
	(via
		(at 358.170734 -246.364506)
		(size 0.4572)
		(drill 0.2032)
		(layers "F.Cu" "B.Cu")
		(net "GND")
	)
	(via
		(at 129.966212 -234.970066)
		(size 0.4572)
		(drill 0.2032)
		(layers "F.Cu" "B.Cu")
		(net "GND")
	)
	(via
		(at 462.555082 -308.666642)
		(size 0.4572)
		(drill 0.2032)
		(layers "F.Cu" "B.Cu")
		(net "GND")
	)
	(via
		(at 135.605266 -220.319854)
		(size 0.4572)
		(drill 0.2032)
		(layers "F.Cu" "B.Cu")
		(net "GND")
	)
	(via
		(at 377.59894 -336.765392)
		(size 0.49022)
		(drill 0.254)
		(layers "F.Cu" "B.Cu")
		(net "GND")
	)
	(via
		(at 350.774762 -249.242326)
		(size 0.4572)
		(drill 0.2032)
		(layers "F.Cu" "B.Cu")
		(net "GND")
	)
	(via
		(at 351.077276 -409.396184)
		(size 0.4572)
		(drill 0.254)
		(layers "F.Cu" "B.Cu")
		(net "GND")
	)
	(via
		(at 187.883546 -306.116736)
		(size 0.4572)
		(drill 0.2032)
		(layers "F.Cu" "B.Cu")
		(net "GND")
	)
	(via
		(at 242.545616 -57.338214)
		(size 0.508)
		(drill 0.254)
		(layers "F.Cu" "B.Cu")
		(net "GND")
	)
	(via
		(at 381.673862 -400.224244)
		(size 0.4572)
		(drill 0.254)
		(layers "F.Cu" "B.Cu")
		(net "GND")
	)
	(via
		(at 74.89317 -406.370536)
		(size 0.4572)
		(drill 0.254)
		(layers "F.Cu" "B.Cu")
		(net "GND")
	)
	(via
		(at 446.389506 -72.113394)
		(size 0.508)
		(drill 0.254)
		(layers "F.Cu" "B.Cu")
		(net "GND")
	)
	(via
		(at 436.924196 -382.49733)
		(size 0.508)
		(drill 0.254)
		(layers "F.Cu" "B.Cu")
		(net "GND")
	)
	(via
		(at 432.379882 -205.816708)
		(size 0.4572)
		(drill 0.2032)
		(layers "F.Cu" "B.Cu")
		(net "GND")
	)
	(via
		(at 339.623908 -52.49545)
		(size 0.4572)
		(drill 0.2032)
		(layers "F.Cu" "B.Cu")
		(net "GND")
	)
	(via
		(at 406.099772 -17.601438)
		(size 0.508)
		(drill 0.254)
		(layers "F.Cu" "B.Cu")
		(net "GND")
	)
	(via
		(at 311.882282 -277.216616)
		(size 0.4572)
		(drill 0.2032)
		(layers "F.Cu" "B.Cu")
		(net "GND")
	)
	(via
		(at 382.35001 -432.747166)
		(size 0.4572)
		(drill 0.2032)
		(layers "F.Cu" "B.Cu")
		(net "GND")
	)
	(via
		(at 307.782214 -317.166752)
		(size 0.4572)
		(drill 0.2032)
		(layers "F.Cu" "B.Cu")
		(net "GND")
	)
	(via
		(at 333.95666 -406.370536)
		(size 0.4572)
		(drill 0.254)
		(layers "F.Cu" "B.Cu")
		(net "GND")
	)
	(via
		(at 2.764536 -178.230022)
		(size 0.508)
		(drill 0.254)
		(layers "F.Cu" "B.Cu")
		(net "GND")
	)
	(via
		(at 59.842146 -242.3668)
		(size 0.4572)
		(drill 0.2032)
		(layers "F.Cu" "B.Cu")
		(net "GND")
	)
	(via
		(at 239.432084 -101.801422)
		(size 0.508)
		(drill 0.254)
		(layers "F.Cu" "B.Cu")
		(net "GND")
	)
	(via
		(at 7.035546 -295.06672)
		(size 0.4572)
		(drill 0.2032)
		(layers "F.Cu" "B.Cu")
		(net "GND")
	)
	(via
		(at 131.846066 -239.853216)
		(size 0.4572)
		(drill 0.2032)
		(layers "F.Cu" "B.Cu")
		(net "GND")
	)
	(via
		(at 460.664814 -287.416748)
		(size 0.4572)
		(drill 0.2032)
		(layers "F.Cu" "B.Cu")
		(net "GND")
	)
	(via
		(at 279.816814 -233.016806)
		(size 0.4572)
		(drill 0.2032)
		(layers "F.Cu" "B.Cu")
		(net "GND")
	)
	(via
		(at 352.172016 -273.453098)
		(size 0.4572)
		(drill 0.2032)
		(layers "F.Cu" "B.Cu")
		(net "GND")
	)
	(via
		(at 119.158766 -226.017328)
		(size 0.4572)
		(drill 0.2032)
		(layers "F.Cu" "B.Cu")
		(net "GND")
	)
	(via
		(at 113.989866 -226.831144)
		(size 0.4572)
		(drill 0.2032)
		(layers "F.Cu" "B.Cu")
		(net "GND")
	)
	(via
		(at 18.679414 -194.766692)
		(size 0.4572)
		(drill 0.2032)
		(layers "F.Cu" "B.Cu")
		(net "GND")
	)
	(via
		(at 462.555082 -272.966688)
		(size 0.4572)
		(drill 0.2032)
		(layers "F.Cu" "B.Cu")
		(net "GND")
	)
	(via
		(at 294.904414 -273.816572)
		(size 0.4572)
		(drill 0.2032)
		(layers "F.Cu" "B.Cu")
		(net "GND")
	)
	(via
		(at 353.001834 -226.017328)
		(size 0.4572)
		(drill 0.2032)
		(layers "F.Cu" "B.Cu")
		(net "GND")
	)
	(via
		(at 420.14013 -407.00452)
		(size 0.4064)
		(drill 0.2032)
		(layers "F.Cu" "B.Cu")
		(net "GND")
	)
	(via
		(at 103.71455 -262.704834)
		(size 0.4572)
		(drill 0.2032)
		(layers "F.Cu" "B.Cu")
		(net "GND")
	)
	(via
		(at 46.964346 -238.966756)
		(size 0.4572)
		(drill 0.2032)
		(layers "F.Cu" "B.Cu")
		(net "GND")
	)
	(via
		(at 47.21733 -390.007348)
		(size 0.508)
		(drill 0.254)
		(layers "F.Cu" "B.Cu")
		(net "GND")
	)
	(via
		(at 209.281014 -277.216616)
		(size 0.4572)
		(drill 0.2032)
		(layers "F.Cu" "B.Cu")
		(net "GND")
	)
	(via
		(at 11.135614 -194.766692)
		(size 0.4572)
		(drill 0.2032)
		(layers "F.Cu" "B.Cu")
		(net "GND")
	)
	(via
		(at 94.833948 -276.708616)
		(size 0.4572)
		(drill 0.2032)
		(layers "F.Cu" "B.Cu")
		(net "GND")
	)
	(via
		(at 180.339746 -208.366614)
		(size 0.4572)
		(drill 0.2032)
		(layers "F.Cu" "B.Cu")
		(net "GND")
	)
	(via
		(at 409.748482 -239.81664)
		(size 0.4572)
		(drill 0.2032)
		(layers "F.Cu" "B.Cu")
		(net "GND")
	)
	(via
		(at 419.502082 -305.266598)
		(size 0.4572)
		(drill 0.2032)
		(layers "F.Cu" "B.Cu")
		(net "GND")
	)
	(via
		(at 329.28687 -341.063072)
		(size 0.49022)
		(drill 0.254)
		(layers "F.Cu" "B.Cu")
		(net "GND")
	)
	(via
		(at 55.16753 -403.249892)
		(size 0.4572)
		(drill 0.254)
		(layers "F.Cu" "B.Cu")
		(net "GND")
	)
	(via
		(at 125.267466 -244.73662)
		(size 0.4572)
		(drill 0.2032)
		(layers "F.Cu" "B.Cu")
		(net "GND")
	)
	(via
		(at 407.34996 -427.851316)
		(size 0.4572)
		(drill 0.2032)
		(layers "F.Cu" "B.Cu")
		(net "GND")
	)
	(via
		(at 296.578782 -275.516594)
		(size 0.4572)
		(drill 0.2032)
		(layers "F.Cu" "B.Cu")
		(net "GND")
	)
	(via
		(at 59.842146 -234.716574)
		(size 0.4572)
		(drill 0.2032)
		(layers "F.Cu" "B.Cu")
		(net "GND")
	)
	(via
		(at 449.08343 -74.990452)
		(size 0.508)
		(drill 0.254)
		(layers "F.Cu" "B.Cu")
		(net "GND")
	)
	(via
		(at 364.92688 -393.240768)
		(size 0.508)
		(drill 0.254)
		(layers "F.Cu" "B.Cu")
		(net "GND")
	)
	(via
		(at 137.456418 -337.72475)
		(size 0.6604)
		(drill 0.3302)
		(layers "F.Cu" "B.Cu")
		(net "GND")
	)
	(via
		(at 343.14638 -407.638504)
		(size 0.4572)
		(drill 0.254)
		(layers "F.Cu" "B.Cu")
		(net "GND")
	)
	(via
		(at 159.682434 -410.030168)
		(size 0.4064)
		(drill 0.2032)
		(layers "F.Cu" "B.Cu")
		(net "GND")
	)
	(via
		(at 379.895862 -284.033722)
		(size 0.4572)
		(drill 0.2032)
		(layers "F.Cu" "B.Cu")
		(net "GND")
	)
	(via
		(at 201.737214 -244.066568)
		(size 0.4572)
		(drill 0.2032)
		(layers "F.Cu" "B.Cu")
		(net "GND")
	)
	(via
		(at 69.31533 -441.225432)
		(size 0.508)
		(drill 0.254)
		(layers "F.Cu" "B.Cu")
		(net "GND")
	)
	(via
		(at 348.302834 -222.761556)
		(size 0.4572)
		(drill 0.2032)
		(layers "F.Cu" "B.Cu")
		(net "GND")
	)
	(via
		(at 108.351066 -226.831144)
		(size 0.4572)
		(drill 0.2032)
		(layers "F.Cu" "B.Cu")
		(net "GND")
	)
	(via
		(at 170.011598 -351.614994)
		(size 0.49022)
		(drill 0.254)
		(layers "F.Cu" "B.Cu")
		(net "GND")
	)
	(via
		(at 422.945814 -201.56678)
		(size 0.4572)
		(drill 0.2032)
		(layers "F.Cu" "B.Cu")
		(net "GND")
	)
	(via
		(at 453.121014 -292.516814)
		(size 0.4572)
		(drill 0.2032)
		(layers "F.Cu" "B.Cu")
		(net "GND")
	)
	(via
		(at 284.778196 -361.374944)
		(size 0.508)
		(drill 0.254)
		(layers "F.Cu" "B.Cu")
		(net "GND")
	)
	(via
		(at 46.964346 -240.666778)
		(size 0.4572)
		(drill 0.2032)
		(layers "F.Cu" "B.Cu")
		(net "GND")
	)
	(via
		(at 418.432742 -401.492212)
		(size 0.4572)
		(drill 0.254)
		(layers "F.Cu" "B.Cu")
		(net "GND")
	)
	(via
		(at 130.906012 -244.73662)
		(size 0.4572)
		(drill 0.2032)
		(layers "F.Cu" "B.Cu")
		(net "GND")
	)
	(via
		(at 403.349968 -436.347362)
		(size 0.4572)
		(drill 0.2032)
		(layers "F.Cu" "B.Cu")
		(net "GND")
	)
	(via
		(at 276.373082 -247.466612)
		(size 0.4572)
		(drill 0.2032)
		(layers "F.Cu" "B.Cu")
		(net "GND")
	)
	(via
		(at 458.455014 -250.016772)
		(size 0.4572)
		(drill 0.2032)
		(layers "F.Cu" "B.Cu")
		(net "GND")
	)
	(via
		(at 129.606548 -276.708616)
		(size 0.4572)
		(drill 0.2032)
		(layers "F.Cu" "B.Cu")
		(net "GND")
	)
	(via
		(at 128.556766 -232.528364)
		(size 0.4572)
		(drill 0.2032)
		(layers "F.Cu" "B.Cu")
		(net "GND")
	)
	(via
		(at 422.945814 -227.066602)
		(size 0.4572)
		(drill 0.2032)
		(layers "F.Cu" "B.Cu")
		(net "GND")
	)
	(via
		(at 20.889214 -277.216616)
		(size 0.4572)
		(drill 0.2032)
		(layers "F.Cu" "B.Cu")
		(net "GND")
	)
	(via
		(at 296.794682 -215.166702)
		(size 0.4572)
		(drill 0.2032)
		(layers "F.Cu" "B.Cu")
		(net "GND")
	)
	(via
		(at 31.876746 -290.816792)
		(size 0.4572)
		(drill 0.2032)
		(layers "F.Cu" "B.Cu")
		(net "GND")
	)
	(via
		(at 114.68608 -123.148598)
		(size 0.508)
		(drill 0.254)
		(layers "F.Cu" "B.Cu")
		(net "GND")
	)
	(via
		(at 181.02072 -352.404172)
		(size 0.49022)
		(drill 0.254)
		(layers "F.Cu" "B.Cu")
		(net "GND")
	)
	(via
		(at 117.823996 -257.69316)
		(size 0.4572)
		(drill 0.2032)
		(layers "F.Cu" "B.Cu")
		(net "GND")
	)
	(via
		(at 87.675466 -236.597952)
		(size 0.4572)
		(drill 0.2032)
		(layers "F.Cu" "B.Cu")
		(net "GND")
	)
	(via
		(at 226.967288 -127.7747)
		(size 0.508)
		(drill 0.254)
		(layers "F.Cu" "B.Cu")
		(net "GND")
	)
	(via
		(at 18.679414 -258.516628)
		(size 0.4572)
		(drill 0.2032)
		(layers "F.Cu" "B.Cu")
		(net "GND")
	)
	(via
		(at 293.093902 -360.833924)
		(size 0.508)
		(drill 0.254)
		(layers "F.Cu" "B.Cu")
		(net "GND")
	)
	(via
		(at 266.619482 -194.766692)
		(size 0.4572)
		(drill 0.2032)
		(layers "F.Cu" "B.Cu")
		(net "GND")
	)
	(via
		(at 121.642886 -339.353652)
		(size 0.508)
		(drill 0.254)
		(layers "F.Cu" "B.Cu")
		(net "GND")
	)
	(via
		(at 207.071214 -305.266598)
		(size 0.4572)
		(drill 0.2032)
		(layers "F.Cu" "B.Cu")
		(net "GND")
	)
	(via
		(at 175.005746 -204.96657)
		(size 0.4572)
		(drill 0.2032)
		(layers "F.Cu" "B.Cu")
		(net "GND")
	)
	(via
		(at 138.534648 -262.872474)
		(size 0.4572)
		(drill 0.2032)
		(layers "F.Cu" "B.Cu")
		(net "GND")
	)
	(via
		(at 184.439814 -232.166668)
		(size 0.4572)
		(drill 0.2032)
		(layers "F.Cu" "B.Cu")
		(net "GND")
	)
	(via
		(at 137.014966 -230.900478)
		(size 0.4318)
		(drill 0.2032)
		(layers "F.Cu" "B.Cu")
		(net "GND")
	)
	(via
		(at 213.954614 -120.457214)
		(size 0.508)
		(drill 0.254)
		(layers "F.Cu" "B.Cu")
		(net "GND")
	)
	(via
		(at 90.494866 -244.73662)
		(size 0.4572)
		(drill 0.2032)
		(layers "F.Cu" "B.Cu")
		(net "GND")
	)
	(via
		(at 212.724746 -195.616576)
		(size 0.4572)
		(drill 0.2032)
		(layers "F.Cu" "B.Cu")
		(net "GND")
	)
	(via
		(at 254.975614 -199.01662)
		(size 0.4572)
		(drill 0.2032)
		(layers "F.Cu" "B.Cu")
		(net "GND")
	)
	(via
		(at 11.135614 -288.266632)
		(size 0.4572)
		(drill 0.2032)
		(layers "F.Cu" "B.Cu")
		(net "GND")
	)
	(via
		(at 354.881434 -229.272846)
		(size 0.4572)
		(drill 0.2032)
		(layers "F.Cu" "B.Cu")
		(net "GND")
	)
	(via
		(at 442.133482 -271.266666)
		(size 0.4572)
		(drill 0.2032)
		(layers "F.Cu" "B.Cu")
		(net "GND")
	)
	(via
		(at 456.520296 -41.01211)
		(size 0.508)
		(drill 0.254)
		(layers "F.Cu" "B.Cu")
		(net "GND")
	)
	(via
		(at 124.34189 -12.534138)
		(size 0.508)
		(drill 0.254)
		(layers "F.Cu" "B.Cu")
		(net "GND")
	)
	(via
		(at 340.784434 -232.528364)
		(size 0.4572)
		(drill 0.2032)
		(layers "F.Cu" "B.Cu")
		(net "GND")
	)
	(via
		(at 113.629694 -288.103056)
		(size 0.4572)
		(drill 0.2032)
		(layers "F.Cu" "B.Cu")
		(net "GND")
	)
	(via
		(at 169.075354 -310.366664)
		(size 0.4572)
		(drill 0.2032)
		(layers "F.Cu" "B.Cu")
		(net "GND")
	)
	(via
		(at 411.958282 -267.866622)
		(size 0.4572)
		(drill 0.2032)
		(layers "F.Cu" "B.Cu")
		(net "GND")
	)
	(via
		(at 115.433602 -252.805946)
		(size 0.4572)
		(drill 0.2032)
		(layers "F.Cu" "B.Cu")
		(net "GND")
	)
	(via
		(at 353.941634 -222.761556)
		(size 0.4572)
		(drill 0.2032)
		(layers "F.Cu" "B.Cu")
		(net "GND")
	)
	(via
		(at 82.250026 -434.899562)
		(size 0.4572)
		(drill 0.2032)
		(layers "F.Cu" "B.Cu")
		(net "GND")
	)
	(via
		(at 270.063214 -214.316564)
		(size 0.4572)
		(drill 0.2032)
		(layers "F.Cu" "B.Cu")
		(net "GND")
	)
	(via
		(at 63.942214 -289.966654)
		(size 0.4572)
		(drill 0.2032)
		(layers "F.Cu" "B.Cu")
		(net "GND")
	)
	(via
		(at 366.60455 -358.157272)
		(size 0.508)
		(drill 0.254)
		(layers "F.Cu" "B.Cu")
		(net "GND")
	)
	(via
		(at 60.551822 -144.90446)
		(size 0.508)
		(drill 0.254)
		(layers "F.Cu" "B.Cu")
		(net "GND")
	)
	(via
		(at 95.193612 -239.853216)
		(size 0.4572)
		(drill 0.2032)
		(layers "F.Cu" "B.Cu")
		(net "GND")
	)
	(via
		(at 420.736014 -273.816572)
		(size 0.4572)
		(drill 0.2032)
		(layers "F.Cu" "B.Cu")
		(net "GND")
	)
	(via
		(at 332.32598 -232.528364)
		(size 0.4572)
		(drill 0.2032)
		(layers "F.Cu" "B.Cu")
		(net "GND")
	)
	(via
		(at 159.918146 -248.31675)
		(size 0.4572)
		(drill 0.2032)
		(layers "F.Cu" "B.Cu")
		(net "GND")
	)
	(via
		(at 123.387866 -220.319854)
		(size 0.4572)
		(drill 0.2032)
		(layers "F.Cu" "B.Cu")
		(net "GND")
	)
	(via
		(at 186.23788 -98.643948)
		(size 0.508)
		(drill 0.254)
		(layers "F.Cu" "B.Cu")
		(net "GND")
	)
	(via
		(at 369.387628 -332.56601)
		(size 0.49022)
		(drill 0.254)
		(layers "F.Cu" "B.Cu")
		(net "GND")
	)
	(via
		(at 78.317598 -410.030168)
		(size 0.4064)
		(drill 0.2032)
		(layers "F.Cu" "B.Cu")
		(net "GND")
	)
	(via
		(at 176.896014 -200.716642)
		(size 0.4572)
		(drill 0.2032)
		(layers "F.Cu" "B.Cu")
		(net "GND")
	)
	(via
		(at 0.76454 -56.720232)
		(size 0.508)
		(drill 0.254)
		(layers "F.Cu" "B.Cu")
		(net "GND")
	)
	(via
		(at 138.534394 -271.011396)
		(size 0.4572)
		(drill 0.2032)
		(layers "F.Cu" "B.Cu")
		(net "GND")
	)
	(via
		(at 135.605266 -243.108988)
		(size 0.4572)
		(drill 0.2032)
		(layers "F.Cu" "B.Cu")
		(net "GND")
	)
	(via
		(at 64.35725 -404.51786)
		(size 0.4572)
		(drill 0.254)
		(layers "F.Cu" "B.Cu")
		(net "GND")
	)
	(via
		(at 127.907288 -357.514906)
		(size 0.508)
		(drill 0.254)
		(layers "F.Cu" "B.Cu")
		(net "GND")
	)
	(via
		(at 199.527414 -277.216616)
		(size 0.4572)
		(drill 0.2032)
		(layers "F.Cu" "B.Cu")
		(net "GND")
	)
	(via
		(at 117.389148 -266.941808)
		(size 0.4572)
		(drill 0.2032)
		(layers "F.Cu" "B.Cu")
		(net "GND")
	)
	(via
		(at 467.535514 -383.40538)
		(size 0.508)
		(drill 0.254)
		(layers "F.Cu" "B.Cu")
		(net "GND")
	)
	(via
		(at 119.628666 -220.319854)
		(size 0.4572)
		(drill 0.2032)
		(layers "F.Cu" "B.Cu")
		(net "GND")
	)
	(via
		(at 167.461946 -290.816792)
		(size 0.4572)
		(drill 0.2032)
		(layers "F.Cu" "B.Cu")
		(net "GND")
	)
	(via
		(at 291.460682 -277.216616)
		(size 0.4572)
		(drill 0.2032)
		(layers "F.Cu" "B.Cu")
		(net "GND")
	)
	(via
		(at 167.82288 -102.707948)
		(size 0.508)
		(drill 0.254)
		(layers "F.Cu" "B.Cu")
		(net "GND")
	)
	(via
		(at 363.143038 -201.20991)
		(size 0.6604)
		(drill 0.3302)
		(layers "F.Cu" "B.Cu")
		(net "GND")
	)
	(via
		(at 47.634906 -19.770344)
		(size 0.508)
		(drill 0.254)
		(layers "F.Cu" "B.Cu")
		(net "GND")
	)
	(via
		(at 136.654794 -271.011396)
		(size 0.4318)
		(drill 0.2032)
		(layers "F.Cu" "B.Cu")
		(net "GND")
	)
	(via
		(at 373.787162 -257.175254)
		(size 0.4572)
		(drill 0.2032)
		(layers "F.Cu" "B.Cu")
		(net "GND")
	)
	(via
		(at 365.03356 -400.307048)
		(size 0.508)
		(drill 0.254)
		(layers "F.Cu" "B.Cu")
		(net "GND")
	)
	(via
		(at 352.3361 -406.370536)
		(size 0.4572)
		(drill 0.254)
		(layers "F.Cu" "B.Cu")
		(net "GND")
	)
	(via
		(at 102.834694 -250.550934)
		(size 0.4572)
		(drill 0.2032)
		(layers "F.Cu" "B.Cu")
		(net "GND")
	)
	(via
		(at 268.829282 -216.866724)
		(size 0.4572)
		(drill 0.2032)
		(layers "F.Cu" "B.Cu")
		(net "GND")
	)
	(via
		(at 304.338482 -294.216582)
		(size 0.4572)
		(drill 0.2032)
		(layers "F.Cu" "B.Cu")
		(net "GND")
	)
	(via
		(at 329.634596 -410.664152)
		(size 0.4572)
		(drill 0.254)
		(layers "F.Cu" "B.Cu")
		(net "GND")
	)
	(via
		(at 459.041246 -68.487036)
		(size 0.508)
		(drill 0.254)
		(layers "F.Cu" "B.Cu")
		(net "GND")
	)
	(via
		(at 184.439814 -275.516594)
		(size 0.4572)
		(drill 0.2032)
		(layers "F.Cu" "B.Cu")
		(net "GND")
	)
	(via
		(at 297.625008 -354.868226)
		(size 0.508)
		(drill 0.254)
		(layers "F.Cu" "B.Cu")
		(net "GND")
	)
	(via
		(at 29.666946 -285.716726)
		(size 0.4572)
		(drill 0.2032)
		(layers "F.Cu" "B.Cu")
		(net "GND")
	)
	(via
		(at 114.099848 -275.8948)
		(size 0.4572)
		(drill 0.2032)
		(layers "F.Cu" "B.Cu")
		(net "GND")
	)
	(via
		(at 71.05396 -52.314348)
		(size 0.508)
		(drill 0.254)
		(layers "F.Cu" "B.Cu")
		(net "GND")
	)
	(via
		(at 81.477866 -403.249892)
		(size 0.4572)
		(drill 0.254)
		(layers "F.Cu" "B.Cu")
		(net "GND")
	)
	(via
		(at 432.379882 -196.466714)
		(size 0.4572)
		(drill 0.2032)
		(layers "F.Cu" "B.Cu")
		(net "GND")
	)
	(via
		(at 95.663766 -226.017328)
		(size 0.4572)
		(drill 0.2032)
		(layers "F.Cu" "B.Cu")
		(net "GND")
	)
	(via
		(at 184.439814 -312.91657)
		(size 0.4572)
		(drill 0.2032)
		(layers "F.Cu" "B.Cu")
		(net "GND")
	)
	(via
		(at 325.250048 -438.499758)
		(size 0.4572)
		(drill 0.2032)
		(layers "F.Cu" "B.Cu")
		(net "GND")
	)
	(via
		(at 51.064414 -249.166634)
		(size 0.4572)
		(drill 0.2032)
		(layers "F.Cu" "B.Cu")
		(net "GND")
	)
	(via
		(at 88.145366 -335.976214)
		(size 0.49022)
		(drill 0.254)
		(layers "F.Cu" "B.Cu")
		(net "GND")
	)
	(via
		(at 277.607014 -236.416596)
		(size 0.4572)
		(drill 0.2032)
		(layers "F.Cu" "B.Cu")
		(net "GND")
	)
	(via
		(at 43.520614 -280.61666)
		(size 0.4572)
		(drill 0.2032)
		(layers "F.Cu" "B.Cu")
		(net "GND")
	)
	(via
		(at 159.056578 -189.88659)
		(size 0.508)
		(drill 0.254)
		(layers "F.Cu" "B.Cu")
		(net "GND")
	)
	(via
		(at 86.845394 -257.98907)
		(size 0.4572)
		(drill 0.2032)
		(layers "F.Cu" "B.Cu")
		(net "GND")
	)
	(via
		(at 409.69692 -158.435548)
		(size 0.508)
		(drill 0.254)
		(layers "F.Cu" "B.Cu")
		(net "GND")
	)
	(via
		(at 380.835916 -269.38351)
		(size 0.4572)
		(drill 0.2032)
		(layers "F.Cu" "B.Cu")
		(net "GND")
	)
	(via
		(at 139.364212 -236.597952)
		(size 0.4572)
		(drill 0.2032)
		(layers "F.Cu" "B.Cu")
		(net "GND")
	)
	(via
		(at 257.185414 -267.016738)
		(size 0.4572)
		(drill 0.2032)
		(layers "F.Cu" "B.Cu")
		(net "GND")
	)
	(via
		(at 54.07533 -441.225432)
		(size 0.508)
		(drill 0.254)
		(layers "F.Cu" "B.Cu")
		(net "GND")
	)
	(via
		(at 418.641276 -5.585714)
		(size 0.508)
		(drill 0.254)
		(layers "F.Cu" "B.Cu")
		(net "GND")
	)
	(via
		(at 457.221082 -207.51673)
		(size 0.4572)
		(drill 0.2032)
		(layers "F.Cu" "B.Cu")
		(net "GND")
	)
	(via
		(at 337.49488 -246.364506)
		(size 0.4572)
		(drill 0.2032)
		(layers "F.Cu" "B.Cu")
		(net "GND")
	)
	(via
		(at 398.225772 -18.491454)
		(size 0.508)
		(drill 0.254)
		(layers "F.Cu" "B.Cu")
		(net "GND")
	)
	(via
		(at 35.976814 -211.766658)
		(size 0.4572)
		(drill 0.2032)
		(layers "F.Cu" "B.Cu")
		(net "GND")
	)
	(via
		(at 97.653348 -263.686544)
		(size 0.4572)
		(drill 0.2032)
		(layers "F.Cu" "B.Cu")
		(net "GND")
	)
	(via
		(at 210.514946 -248.31675)
		(size 0.4572)
		(drill 0.2032)
		(layers "F.Cu" "B.Cu")
		(net "GND")
	)
	(via
		(at 239.175036 -50.558954)
		(size 0.508)
		(drill 0.254)
		(layers "F.Cu" "B.Cu")
		(net "GND")
	)
	(via
		(at 140.349986 -426.54728)
		(size 0.4572)
		(drill 0.2032)
		(layers "F.Cu" "B.Cu")
		(net "GND")
	)
	(via
		(at 191.983614 -239.81664)
		(size 0.4572)
		(drill 0.2032)
		(layers "F.Cu" "B.Cu")
		(net "GND")
	)
	(via
		(at 377.076462 -269.38351)
		(size 0.4572)
		(drill 0.2032)
		(layers "F.Cu" "B.Cu")
		(net "GND")
	)
	(via
		(at 279.816814 -283.166566)
		(size 0.4572)
		(drill 0.2032)
		(layers "F.Cu" "B.Cu")
		(net "GND")
	)
	(via
		(at 419.778942 -407.638504)
		(size 0.4572)
		(drill 0.254)
		(layers "F.Cu" "B.Cu")
		(net "GND")
	)
	(via
		(at 283.916882 -211.766658)
		(size 0.4572)
		(drill 0.2032)
		(layers "F.Cu" "B.Cu")
		(net "GND")
	)
	(via
		(at 78.664054 -341.766906)
		(size 0.49022)
		(drill 0.254)
		(layers "F.Cu" "B.Cu")
		(net "GND")
	)
	(via
		(at 432.379882 -303.566576)
		(size 0.4572)
		(drill 0.2032)
		(layers "F.Cu" "B.Cu")
		(net "GND")
	)
	(via
		(at 346.063316 -279.150318)
		(size 0.4572)
		(drill 0.2032)
		(layers "F.Cu" "B.Cu")
		(net "GND")
	)
	(via
		(at 135.424418 -337.72475)
		(size 0.6604)
		(drill 0.3302)
		(layers "F.Cu" "B.Cu")
		(net "GND")
	)
	(via
		(at 61.212222 -144.90446)
		(size 0.508)
		(drill 0.254)
		(layers "F.Cu" "B.Cu")
		(net "GND")
	)
	(via
		(at 426.25137 -4.317746)
		(size 0.508)
		(drill 0.254)
		(layers "F.Cu" "B.Cu")
		(net "GND")
	)
	(via
		(at 48.962818 -359.08615)
		(size 0.508)
		(drill 0.254)
		(layers "F.Cu" "B.Cu")
		(net "GND")
	)
	(via
		(at 414.85947 -163.538154)
		(size 0.49022)
		(drill 0.254)
		(layers "F.Cu" "B.Cu")
		(net "GND")
	)
	(via
		(at 115.82908 -401.424648)
		(size 0.508)
		(drill 0.254)
		(layers "F.Cu" "B.Cu")
		(net "GND")
	)
	(via
		(at 147.349972 -431.451258)
		(size 0.4572)
		(drill 0.2032)
		(layers "F.Cu" "B.Cu")
		(net "GND")
	)
	(via
		(at 39.420546 -203.266802)
		(size 0.4572)
		(drill 0.2032)
		(layers "F.Cu" "B.Cu")
		(net "GND")
	)
	(via
		(at 209.281014 -196.466714)
		(size 0.4572)
		(drill 0.2032)
		(layers "F.Cu" "B.Cu")
		(net "GND")
	)
	(via
		(at 19.284188 -397.477996)
		(size 0.508)
		(drill 0.254)
		(layers "F.Cu" "B.Cu")
		(net "GND")
	)
	(via
		(at 427.045882 -271.266666)
		(size 0.4572)
		(drill 0.2032)
		(layers "F.Cu" "B.Cu")
		(net "GND")
	)
	(via
		(at 287.360614 -261.916672)
		(size 0.4572)
		(drill 0.2032)
		(layers "F.Cu" "B.Cu")
		(net "GND")
	)
	(via
		(at 339.954362 -255.547622)
		(size 0.4572)
		(drill 0.2032)
		(layers "F.Cu" "B.Cu")
		(net "GND")
	)
	(via
		(at 304.338482 -284.866588)
		(size 0.4572)
		(drill 0.2032)
		(layers "F.Cu" "B.Cu")
		(net "GND")
	)
	(via
		(at 432.379882 -200.716642)
		(size 0.4572)
		(drill 0.2032)
		(layers "F.Cu" "B.Cu")
		(net "GND")
	)
	(via
		(at 334.899508 -47.250096)
		(size 0.4572)
		(drill 0.2032)
		(layers "F.Cu" "B.Cu")
		(net "GND")
	)
	(via
		(at 304.2158 -363.898688)
		(size 0.49022)
		(drill 0.254)
		(layers "F.Cu" "B.Cu")
		(net "GND")
	)
	(via
		(at 341.105998 -47.040546)
		(size 0.4572)
		(drill 0.2032)
		(layers "F.Cu" "B.Cu")
		(net "GND")
	)
	(via
		(at 340.314534 -244.73662)
		(size 0.4572)
		(drill 0.2032)
		(layers "F.Cu" "B.Cu")
		(net "GND")
	)
	(via
		(at 88.724994 -285.661354)
		(size 0.4572)
		(drill 0.2032)
		(layers "F.Cu" "B.Cu")
		(net "GND")
	)
	(via
		(at 260.524752 -323.429376)
		(size 0.4572)
		(drill 0.2032)
		(layers "F.Cu" "B.Cu")
		(net "GND")
	)
	(via
		(at 419.502082 -244.066568)
		(size 0.4572)
		(drill 0.2032)
		(layers "F.Cu" "B.Cu")
		(net "GND")
	)
	(via
		(at 197.699884 -319.345056)
		(size 0.4572)
		(drill 0.2032)
		(layers "F.Cu" "B.Cu")
		(net "GND")
	)
	(via
		(at 134.305548 -255.547622)
		(size 0.4572)
		(drill 0.2032)
		(layers "F.Cu" "B.Cu")
		(net "GND")
	)
	(via
		(at 31.876746 -248.31675)
		(size 0.4572)
		(drill 0.2032)
		(layers "F.Cu" "B.Cu")
		(net "GND")
	)
	(via
		(at 335.615534 -243.108988)
		(size 0.4572)
		(drill 0.2032)
		(layers "F.Cu" "B.Cu")
		(net "GND")
	)
	(via
		(at 29.666946 -251.716794)
		(size 0.4572)
		(drill 0.2032)
		(layers "F.Cu" "B.Cu")
		(net "GND")
	)
	(via
		(at 106.581194 -272.639282)
		(size 0.4572)
		(drill 0.2032)
		(layers "F.Cu" "B.Cu")
		(net "GND")
	)
	(via
		(at 134.305548 -268.569694)
		(size 0.4572)
		(drill 0.2032)
		(layers "F.Cu" "B.Cu")
		(net "GND")
	)
	(via
		(at 202.971146 -197.316598)
		(size 0.4572)
		(drill 0.2032)
		(layers "F.Cu" "B.Cu")
		(net "GND")
	)
	(via
		(at 464.764882 -232.166668)
		(size 0.4572)
		(drill 0.2032)
		(layers "F.Cu" "B.Cu")
		(net "GND")
	)
	(via
		(at 20.180554 -177.677318)
		(size 0.508)
		(drill 0.254)
		(layers "F.Cu" "B.Cu")
		(net "GND")
	)
	(via
		(at 61.381386 -406.370536)
		(size 0.4572)
		(drill 0.254)
		(layers "F.Cu" "B.Cu")
		(net "GND")
	)
	(via
		(at 199.527414 -250.866656)
		(size 0.4572)
		(drill 0.2032)
		(layers "F.Cu" "B.Cu")
		(net "GND")
	)
	(via
		(at 47.153322 -359.14203)
		(size 0.508)
		(drill 0.254)
		(layers "F.Cu" "B.Cu")
		(net "GND")
	)
	(via
		(at 18.54708 -12.37488)
		(size 0.508)
		(drill 0.254)
		(layers "F.Cu" "B.Cu")
		(net "GND")
	)
	(via
		(at 292.694614 -295.06672)
		(size 0.4572)
		(drill 0.2032)
		(layers "F.Cu" "B.Cu")
		(net "GND")
	)
	(via
		(at 362.509562 -265.314176)
		(size 0.4572)
		(drill 0.2032)
		(layers "F.Cu" "B.Cu")
		(net "GND")
	)
	(via
		(at 409.330398 -409.396184)
		(size 0.4572)
		(drill 0.254)
		(layers "F.Cu" "B.Cu")
		(net "GND")
	)
	(via
		(at 276.373082 -278.916638)
		(size 0.4572)
		(drill 0.2032)
		(layers "F.Cu" "B.Cu")
		(net "GND")
	)
	(via
		(at 87.604346 -403.249892)
		(size 0.4572)
		(drill 0.254)
		(layers "F.Cu" "B.Cu")
		(net "GND")
	)
	(via
		(at 443.367414 -225.36658)
		(size 0.4572)
		(drill 0.2032)
		(layers "F.Cu" "B.Cu")
		(net "GND")
	)
	(via
		(at 255.7145 -101.85654)
		(size 0.508)
		(drill 0.254)
		(layers "F.Cu" "B.Cu")
		(net "GND")
	)
	(via
		(at 270.063214 -317.166752)
		(size 0.4572)
		(drill 0.2032)
		(layers "F.Cu" "B.Cu")
		(net "GND")
	)
	(via
		(at 423.67962 -50.94732)
		(size 0.508)
		(drill 0.254)
		(layers "F.Cu" "B.Cu")
		(net "GND")
	)
	(via
		(at 285.150814 -296.766742)
		(size 0.4572)
		(drill 0.2032)
		(layers "F.Cu" "B.Cu")
		(net "GND")
	)
	(via
		(at 296.794682 -301.01667)
		(size 0.4572)
		(drill 0.2032)
		(layers "F.Cu" "B.Cu")
		(net "GND")
	)
	(via
		(at 44.754546 -301.866808)
		(size 0.4572)
		(drill 0.2032)
		(layers "F.Cu" "B.Cu")
		(net "GND")
	)
	(via
		(at 285.150814 -265.316716)
		(size 0.4572)
		(drill 0.2032)
		(layers "F.Cu" "B.Cu")
		(net "GND")
	)
	(via
		(at 357.4288 -404.2156)
		(size 0.508)
		(drill 0.254)
		(layers "F.Cu" "B.Cu")
		(net "GND")
	)
	(via
		(at 351.59188 -335.704434)
		(size 0.49022)
		(drill 0.254)
		(layers "F.Cu" "B.Cu")
		(net "GND")
	)
	(via
		(at 193.02476 -111.310928)
		(size 0.508)
		(drill 0.254)
		(layers "F.Cu" "B.Cu")
		(net "GND")
	)
	(via
		(at 150.131526 -410.664152)
		(size 0.4572)
		(drill 0.254)
		(layers "F.Cu" "B.Cu")
		(net "GND")
	)
	(via
		(at 329.25004 -430.147222)
		(size 0.4572)
		(drill 0.2032)
		(layers "F.Cu" "B.Cu")
		(net "GND")
	)
	(via
		(at 202.971146 -278.066754)
		(size 0.4572)
		(drill 0.2032)
		(layers "F.Cu" "B.Cu")
		(net "GND")
	)
	(via
		(at 279.816814 -287.416748)
		(size 0.4572)
		(drill 0.2032)
		(layers "F.Cu" "B.Cu")
		(net "GND")
	)
	(via
		(at 39.085266 -183.30164)
		(size 0.508)
		(drill 0.254)
		(layers "F.Cu" "B.Cu")
		(net "GND")
	)
	(via
		(at 264.729214 -203.266802)
		(size 0.4572)
		(drill 0.2032)
		(layers "F.Cu" "B.Cu")
		(net "GND")
	)
	(via
		(at 259.075682 -241.516662)
		(size 0.4572)
		(drill 0.2032)
		(layers "F.Cu" "B.Cu")
		(net "GND")
	)
	(via
		(at 150.89886 -128.297178)
		(size 0.508)
		(drill 0.254)
		(layers "F.Cu" "B.Cu")
		(net "GND")
	)
	(via
		(at 363.953298 -295.038526)
		(size 0.508)
		(drill 0.254)
		(layers "F.Cu" "B.Cu")
		(net "GND")
	)
	(via
		(at 190.093346 -267.016738)
		(size 0.4572)
		(drill 0.2032)
		(layers "F.Cu" "B.Cu")
		(net "GND")
	)
	(via
		(at 154.911806 -403.249892)
		(size 0.4572)
		(drill 0.254)
		(layers "F.Cu" "B.Cu")
		(net "GND")
	)
	(via
		(at 48.59147 -109.274864)
		(size 0.508)
		(drill 0.254)
		(layers "F.Cu" "B.Cu")
		(net "GND")
	)
	(via
		(at 134.2136 -29.02585)
		(size 0.508)
		(drill 0.254)
		(layers "F.Cu" "B.Cu")
		(net "GND")
	)
	(via
		(at 94.723712 -248.806208)
		(size 0.4572)
		(drill 0.2032)
		(layers "F.Cu" "B.Cu")
		(net "GND")
	)
	(via
		(at 266.619482 -250.866656)
		(size 0.4572)
		(drill 0.2032)
		(layers "F.Cu" "B.Cu")
		(net "GND")
	)
	(via
		(at 54.508146 -306.116736)
		(size 0.4572)
		(drill 0.2032)
		(layers "F.Cu" "B.Cu")
		(net "GND")
	)
	(via
		(at 294.904414 -283.166566)
		(size 0.4572)
		(drill 0.2032)
		(layers "F.Cu" "B.Cu")
		(net "GND")
	)
	(via
		(at 237.615984 -49.76495)
		(size 0.508)
		(drill 0.254)
		(layers "F.Cu" "B.Cu")
		(net "GND")
	)
	(via
		(at 378.956062 -272.639282)
		(size 0.4572)
		(drill 0.2032)
		(layers "F.Cu" "B.Cu")
		(net "GND")
	)
	(via
		(at 279.816814 -311.216802)
		(size 0.4572)
		(drill 0.2032)
		(layers "F.Cu" "B.Cu")
		(net "GND")
	)
	(via
		(at 56.398414 -261.066788)
		(size 0.4572)
		(drill 0.2032)
		(layers "F.Cu" "B.Cu")
		(net "GND")
	)
	(via
		(at 274.163282 -294.216582)
		(size 0.4572)
		(drill 0.2032)
		(layers "F.Cu" "B.Cu")
		(net "GND")
	)
	(via
		(at 124.68987 -331.71892)
		(size 0.508)
		(drill 0.254)
		(layers "F.Cu" "B.Cu")
		(net "GND")
	)
	(via
		(at 14.426946 -393.215876)
		(size 0.508)
		(drill 0.254)
		(layers "F.Cu" "B.Cu")
		(net "GND")
	)
	(via
		(at 287.360614 -238.966756)
		(size 0.4572)
		(drill 0.2032)
		(layers "F.Cu" "B.Cu")
		(net "GND")
	)
	(via
		(at 201.737214 -312.91657)
		(size 0.4572)
		(drill 0.2032)
		(layers "F.Cu" "B.Cu")
		(net "GND")
	)
	(via
		(at 124.437394 -280.778204)
		(size 0.4572)
		(drill 0.2032)
		(layers "F.Cu" "B.Cu")
		(net "GND")
	)
	(via
		(at 159.321246 -407.638504)
		(size 0.4572)
		(drill 0.254)
		(layers "F.Cu" "B.Cu")
		(net "GND")
	)
	(via
		(at 139.242038 -340.977728)
		(size 0.49022)
		(drill 0.254)
		(layers "F.Cu" "B.Cu")
		(net "GND")
	)
	(via
		(at 63.726314 -219.41663)
		(size 0.4572)
		(drill 0.2032)
		(layers "F.Cu" "B.Cu")
		(net "GND")
	)
	(via
		(at 96.133412 -241.481102)
		(size 0.4572)
		(drill 0.2032)
		(layers "F.Cu" "B.Cu")
		(net "GND")
	)
	(via
		(at 378.486162 -289.807142)
		(size 0.4572)
		(drill 0.2032)
		(layers "F.Cu" "B.Cu")
		(net "GND")
	)
	(via
		(at 137.594848 -257.98907)
		(size 0.4572)
		(drill 0.2032)
		(layers "F.Cu" "B.Cu")
		(net "GND")
	)
	(via
		(at 292.98646 -155.021788)
		(size 0.508)
		(drill 0.254)
		(layers "F.Cu" "B.Cu")
		(net "GND")
	)
	(via
		(at 266.619482 -262.76681)
		(size 0.4572)
		(drill 0.2032)
		(layers "F.Cu" "B.Cu")
		(net "GND")
	)
	(via
		(at 403.846792 -7.215124)
		(size 0.508)
		(drill 0.254)
		(layers "F.Cu" "B.Cu")
		(net "GND")
	)
	(via
		(at 312.893964 -441.225432)
		(size 0.508)
		(drill 0.254)
		(layers "F.Cu" "B.Cu")
		(net "GND")
	)
	(via
		(at 234.8484 -209.362548)
		(size 0.508)
		(drill 0.254)
		(layers "F.Cu" "B.Cu")
		(net "GND")
	)
	(via
		(at 371.583204 -333.356458)
		(size 0.49022)
		(drill 0.254)
		(layers "F.Cu" "B.Cu")
		(net "GND")
	)
	(via
		(at 62.5856 -143.043148)
		(size 0.508)
		(drill 0.254)
		(layers "F.Cu" "B.Cu")
		(net "GND")
	)
	(via
		(at 415.402014 -231.316784)
		(size 0.4572)
		(drill 0.2032)
		(layers "F.Cu" "B.Cu")
		(net "GND")
	)
	(via
		(at 107.520994 -285.661354)
		(size 0.4572)
		(drill 0.2032)
		(layers "F.Cu" "B.Cu")
		(net "GND")
	)
	(via
		(at 438.033414 -231.316784)
		(size 0.4572)
		(drill 0.2032)
		(layers "F.Cu" "B.Cu")
		(net "GND")
	)
	(via
		(at 407.858214 -267.016738)
		(size 0.4572)
		(drill 0.2032)
		(layers "F.Cu" "B.Cu")
		(net "GND")
	)
	(via
		(at 311.666382 -235.566712)
		(size 0.4572)
		(drill 0.2032)
		(layers "F.Cu" "B.Cu")
		(net "GND")
	)
	(via
		(at 379.956822 -406.370536)
		(size 0.4572)
		(drill 0.254)
		(layers "F.Cu" "B.Cu")
		(net "GND")
	)
	(via
		(at 31.876746 -227.066602)
		(size 0.4572)
		(drill 0.2032)
		(layers "F.Cu" "B.Cu")
		(net "GND")
	)
	(via
		(at 434.589682 -221.116652)
		(size 0.4572)
		(drill 0.2032)
		(layers "F.Cu" "B.Cu")
		(net "GND")
	)
	(via
		(at 136.075166 -235.783882)
		(size 0.4572)
		(drill 0.2032)
		(layers "F.Cu" "B.Cu")
		(net "GND")
	)
	(via
		(at 311.666382 -271.266666)
		(size 0.4572)
		(drill 0.2032)
		(layers "F.Cu" "B.Cu")
		(net "GND")
	)
	(via
		(at 412.306262 -404.51786)
		(size 0.4572)
		(drill 0.254)
		(layers "F.Cu" "B.Cu")
		(net "GND")
	)
	(via
		(at 273.62658 -96.329754)
		(size 0.508)
		(drill 0.254)
		(layers "F.Cu" "B.Cu")
		(net "GND")
	)
	(via
		(at 460.664814 -304.416714)
		(size 0.4572)
		(drill 0.2032)
		(layers "F.Cu" "B.Cu")
		(net "GND")
	)
	(via
		(at 307.782214 -295.06672)
		(size 0.4572)
		(drill 0.2032)
		(layers "F.Cu" "B.Cu")
		(net "GND")
	)
	(via
		(at 274.804124 -120.034558)
		(size 0.508)
		(drill 0.254)
		(layers "F.Cu" "B.Cu")
		(net "GND")
	)
	(via
		(at 184.439814 -211.766658)
		(size 0.4572)
		(drill 0.2032)
		(layers "F.Cu" "B.Cu")
		(net "GND")
	)
	(via
		(at 424.2816 -58.283348)
		(size 0.508)
		(drill 0.254)
		(layers "F.Cu" "B.Cu")
		(net "GND")
	)
	(via
		(at 347.473016 -278.336502)
		(size 0.4572)
		(drill 0.2032)
		(layers "F.Cu" "B.Cu")
		(net "GND")
	)
	(via
		(at 281.707082 -238.116618)
		(size 0.4572)
		(drill 0.2032)
		(layers "F.Cu" "B.Cu")
		(net "GND")
	)
	(via
		(at 133.830314 -400.858228)
		(size 0.4064)
		(drill 0.2032)
		(layers "F.Cu" "B.Cu")
		(net "GND")
	)
	(via
		(at 323.250052 -431.451258)
		(size 0.4572)
		(drill 0.2032)
		(layers "F.Cu" "B.Cu")
		(net "GND")
	)
	(via
		(at 277.607014 -248.31675)
		(size 0.4572)
		(drill 0.2032)
		(layers "F.Cu" "B.Cu")
		(net "GND")
	)
	(via
		(at 210.514946 -309.51678)
		(size 0.4572)
		(drill 0.2032)
		(layers "F.Cu" "B.Cu")
		(net "GND")
	)
	(via
		(at 134.665212 -220.319854)
		(size 0.4572)
		(drill 0.2032)
		(layers "F.Cu" "B.Cu")
		(net "GND")
	)
	(via
		(at 189.13602 -128.658366)
		(size 0.508)
		(drill 0.254)
		(layers "F.Cu" "B.Cu")
		(net "GND")
	)
	(via
		(at 446.659 -58.882788)
		(size 0.508)
		(drill 0.254)
		(layers "F.Cu" "B.Cu")
		(net "GND")
	)
	(via
		(at 366.159034 -222.761556)
		(size 0.4572)
		(drill 0.2032)
		(layers "F.Cu" "B.Cu")
		(net "GND")
	)
	(via
		(at 92.014294 -265.314176)
		(size 0.4572)
		(drill 0.2032)
		(layers "F.Cu" "B.Cu")
		(net "GND")
	)
	(via
		(at 369.448334 -220.319854)
		(size 0.4572)
		(drill 0.2032)
		(layers "F.Cu" "B.Cu")
		(net "GND")
	)
	(via
		(at 29.084778 -102.761034)
		(size 0.508)
		(drill 0.254)
		(layers "F.Cu" "B.Cu")
		(net "GND")
	)
	(via
		(at 405.349964 -431.29962)
		(size 0.4572)
		(drill 0.2032)
		(layers "F.Cu" "B.Cu")
		(net "GND")
	)
	(via
		(at 287.360614 -197.316598)
		(size 0.4572)
		(drill 0.2032)
		(layers "F.Cu" "B.Cu")
		(net "GND")
	)
	(via
		(at 386.350002 -426.69968)
		(size 0.4572)
		(drill 0.2032)
		(layers "F.Cu" "B.Cu")
		(net "GND")
	)
	(via
		(at 455.011282 -280.61666)
		(size 0.4572)
		(drill 0.2032)
		(layers "F.Cu" "B.Cu")
		(net "GND")
	)
	(via
		(at 383.727452 -340.977728)
		(size 0.49022)
		(drill 0.254)
		(layers "F.Cu" "B.Cu")
		(net "GND")
	)
	(via
		(at 372.267734 -226.831144)
		(size 0.4572)
		(drill 0.2032)
		(layers "F.Cu" "B.Cu")
		(net "GND")
	)
	(via
		(at 171.073318 -345.64701)
		(size 0.508)
		(drill 0.254)
		(layers "F.Cu" "B.Cu")
		(net "GND")
	)
	(via
		(at 136.184894 -258.80314)
		(size 0.4572)
		(drill 0.2032)
		(layers "F.Cu" "B.Cu")
		(net "GND")
	)
	(via
		(at 13.345414 -232.166668)
		(size 0.4572)
		(drill 0.2032)
		(layers "F.Cu" "B.Cu")
		(net "GND")
	)
	(via
		(at 180.339746 -206.666592)
		(size 0.4572)
		(drill 0.2032)
		(layers "F.Cu" "B.Cu")
		(net "GND")
	)
	(via
		(at 370.38788 -233.34218)
		(size 0.4572)
		(drill 0.2032)
		(layers "F.Cu" "B.Cu")
		(net "GND")
	)
	(via
		(at 274.163282 -299.316648)
		(size 0.4572)
		(drill 0.2032)
		(layers "F.Cu" "B.Cu")
		(net "GND")
	)
	(via
		(at 102.882192 -237.679484)
		(size 0.4572)
		(drill 0.2032)
		(layers "F.Cu" "B.Cu")
		(net "GND")
	)
	(via
		(at 91.544394 -279.150318)
		(size 0.4572)
		(drill 0.2032)
		(layers "F.Cu" "B.Cu")
		(net "GND")
	)
	(via
		(at 106.471466 -220.319854)
		(size 0.4572)
		(drill 0.2032)
		(layers "F.Cu" "B.Cu")
		(net "GND")
	)
	(via
		(at 387.30428 -239.853216)
		(size 0.4572)
		(drill 0.2032)
		(layers "F.Cu" "B.Cu")
		(net "GND")
	)
	(via
		(at 362.546646 -366.465104)
		(size 0.508)
		(drill 0.254)
		(layers "F.Cu" "B.Cu")
		(net "GND")
	)
	(via
		(at 179.105814 -316.316614)
		(size 0.4572)
		(drill 0.2032)
		(layers "F.Cu" "B.Cu")
		(net "GND")
	)
	(via
		(at 138.743436 -19.670522)
		(size 0.508)
		(drill 0.254)
		(layers "F.Cu" "B.Cu")
		(net "GND")
	)
	(via
		(at 182.675276 -45.17771)
		(size 0.508)
		(drill 0.254)
		(layers "F.Cu" "B.Cu")
		(net "GND")
	)
	(via
		(at 179.105814 -194.766692)
		(size 0.4572)
		(drill 0.2032)
		(layers "F.Cu" "B.Cu")
		(net "GND")
	)
	(via
		(at 167.386 -22.672548)
		(size 0.508)
		(drill 0.254)
		(layers "F.Cu" "B.Cu")
		(net "GND")
	)
	(via
		(at 458.455014 -285.716726)
		(size 0.4572)
		(drill 0.2032)
		(layers "F.Cu" "B.Cu")
		(net "GND")
	)
	(via
		(at 122.68962 -292.95598)
		(size 0.508)
		(drill 0.254)
		(layers "F.Cu" "B.Cu")
		(net "GND")
	)
	(via
		(at 339.644736 -333.173324)
		(size 0.508)
		(drill 0.254)
		(layers "F.Cu" "B.Cu")
		(net "GND")
	)
	(via
		(at 340.784434 -226.017328)
		(size 0.4572)
		(drill 0.2032)
		(layers "F.Cu" "B.Cu")
		(net "GND")
	)
	(via
		(at 187.883546 -248.31675)
		(size 0.4572)
		(drill 0.2032)
		(layers "F.Cu" "B.Cu")
		(net "GND")
	)
	(via
		(at 138.429238 -340.977728)
		(size 0.49022)
		(drill 0.254)
		(layers "F.Cu" "B.Cu")
		(net "GND")
	)
	(via
		(at 407.858214 -240.666778)
		(size 0.4572)
		(drill 0.2032)
		(layers "F.Cu" "B.Cu")
		(net "GND")
	)
	(via
		(at 129.026666 -241.481102)
		(size 0.4572)
		(drill 0.2032)
		(layers "F.Cu" "B.Cu")
		(net "GND")
	)
	(via
		(at 199.527414 -299.316648)
		(size 0.4572)
		(drill 0.2032)
		(layers "F.Cu" "B.Cu")
		(net "GND")
	)
	(via
		(at 424.836082 -247.466612)
		(size 0.4572)
		(drill 0.2032)
		(layers "F.Cu" "B.Cu")
		(net "GND")
	)
	(via
		(at 383.545334 -226.831144)
		(size 0.4572)
		(drill 0.2032)
		(layers "F.Cu" "B.Cu")
		(net "GND")
	)
	(via
		(at 344.183462 -284.033722)
		(size 0.4572)
		(drill 0.2032)
		(layers "F.Cu" "B.Cu")
		(net "GND")
	)
	(via
		(at 20.889214 -213.46668)
		(size 0.4572)
		(drill 0.2032)
		(layers "F.Cu" "B.Cu")
		(net "GND")
	)
	(via
		(at 299.004482 -301.01667)
		(size 0.4572)
		(drill 0.2032)
		(layers "F.Cu" "B.Cu")
		(net "GND")
	)
	(via
		(at 283.916882 -233.86669)
		(size 0.4572)
		(drill 0.2032)
		(layers "F.Cu" "B.Cu")
		(net "GND")
	)
	(via
		(at 438.033414 -217.716608)
		(size 0.4572)
		(drill 0.2032)
		(layers "F.Cu" "B.Cu")
		(net "GND")
	)
	(via
		(at 292.694614 -250.016772)
		(size 0.4572)
		(drill 0.2032)
		(layers "F.Cu" "B.Cu")
		(net "GND")
	)
	(via
		(at 98.49104 -424.457368)
		(size 0.508)
		(drill 0.254)
		(layers "F.Cu" "B.Cu")
		(net "GND")
	)
	(via
		(at 131.015994 -261.244842)
		(size 0.4572)
		(drill 0.2032)
		(layers "F.Cu" "B.Cu")
		(net "GND")
	)
	(via
		(at 422.945814 -272.116804)
		(size 0.4572)
		(drill 0.2032)
		(layers "F.Cu" "B.Cu")
		(net "GND")
	)
	(via
		(at 94.363794 -269.38351)
		(size 0.4572)
		(drill 0.2032)
		(layers "F.Cu" "B.Cu")
		(net "GND")
	)
	(via
		(at 378.376434 -219.506038)
		(size 0.4572)
		(drill 0.2032)
		(layers "F.Cu" "B.Cu")
		(net "GND")
	)
	(via
		(at 443.367414 -240.666778)
		(size 0.4572)
		(drill 0.2032)
		(layers "F.Cu" "B.Cu")
		(net "GND")
	)
	(via
		(at 388.349998 -427.699678)
		(size 0.4572)
		(drill 0.2032)
		(layers "F.Cu" "B.Cu")
		(net "GND")
	)
	(via
		(at 422.945814 -309.51678)
		(size 0.4572)
		(drill 0.2032)
		(layers "F.Cu" "B.Cu")
		(net "GND")
	)
	(via
		(at 292.694614 -231.316784)
		(size 0.4572)
		(drill 0.2032)
		(layers "F.Cu" "B.Cu")
		(net "GND")
	)
	(via
		(at 199.527414 -245.76659)
		(size 0.4572)
		(drill 0.2032)
		(layers "F.Cu" "B.Cu")
		(net "GND")
	)
	(via
		(at 59.842146 -304.416714)
		(size 0.4572)
		(drill 0.2032)
		(layers "F.Cu" "B.Cu")
		(net "GND")
	)
	(via
		(at 46.773338 -113.557812)
		(size 0.508)
		(drill 0.254)
		(layers "F.Cu" "B.Cu")
		(net "GND")
	)
	(via
		(at 41.310814 -196.466714)
		(size 0.4572)
		(drill 0.2032)
		(layers "F.Cu" "B.Cu")
		(net "GND")
	)
	(via
		(at 59.250072 -425.547282)
		(size 0.4572)
		(drill 0.2032)
		(layers "F.Cu" "B.Cu")
		(net "GND")
	)
	(via
		(at 87.315294 -255.547622)
		(size 0.4572)
		(drill 0.2032)
		(layers "F.Cu" "B.Cu")
		(net "GND")
	)
	(via
		(at 351.122234 -216.25052)
		(size 0.4572)
		(drill 0.2032)
		(layers "F.Cu" "B.Cu")
		(net "GND")
	)
	(via
		(at 434.589682 -222.816674)
		(size 0.4572)
		(drill 0.2032)
		(layers "F.Cu" "B.Cu")
		(net "GND")
	)
	(via
		(at 462.555082 -262.76681)
		(size 0.4572)
		(drill 0.2032)
		(layers "F.Cu" "B.Cu")
		(net "GND")
	)
	(via
		(at 376.496834 -237.411514)
		(size 0.4572)
		(drill 0.2032)
		(layers "F.Cu" "B.Cu")
		(net "GND")
	)
	(via
		(at 12.735052 -108.28274)
		(size 0.508)
		(drill 0.254)
		(layers "F.Cu" "B.Cu")
		(net "GND")
	)
	(via
		(at 351.701862 -275.8948)
		(size 0.4572)
		(drill 0.2032)
		(layers "F.Cu" "B.Cu")
		(net "GND")
	)
	(via
		(at 434.715158 -118.168166)
		(size 0.508)
		(drill 0.254)
		(layers "F.Cu" "B.Cu")
		(net "GND")
	)
	(via
		(at 411.349952 -427.851316)
		(size 0.4572)
		(drill 0.2032)
		(layers "F.Cu" "B.Cu")
		(net "GND")
	)
	(via
		(at 108.351066 -213.732618)
		(size 0.4572)
		(drill 0.2032)
		(layers "F.Cu" "B.Cu")
		(net "GND")
	)
	(via
		(at 272.273014 -210.916774)
		(size 0.4572)
		(drill 0.2032)
		(layers "F.Cu" "B.Cu")
		(net "GND")
	)
	(via
		(at 386.44449 -407.00452)
		(size 0.4064)
		(drill 0.2032)
		(layers "F.Cu" "B.Cu")
		(net "GND")
	)
	(via
		(at 365.42472 -16.360648)
		(size 0.508)
		(drill 0.254)
		(layers "F.Cu" "B.Cu")
		(net "GND")
	)
	(via
		(at 336.665062 -287.28924)
		(size 0.4572)
		(drill 0.2032)
		(layers "F.Cu" "B.Cu")
		(net "GND")
	)
	(via
		(at 356.870762 -275.08073)
		(size 0.4572)
		(drill 0.2032)
		(layers "F.Cu" "B.Cu")
		(net "GND")
	)
	(via
		(at 99.532948 -266.941808)
		(size 0.4572)
		(drill 0.2032)
		(layers "F.Cu" "B.Cu")
		(net "GND")
	)
	(via
		(at 259.813552 -323.429376)
		(size 0.4572)
		(drill 0.2032)
		(layers "F.Cu" "B.Cu")
		(net "GND")
	)
	(via
		(at 409.60421 -400.858228)
		(size 0.4064)
		(drill 0.2032)
		(layers "F.Cu" "B.Cu")
		(net "GND")
	)
	(via
		(at 11.873484 -323.434456)
		(size 0.4572)
		(drill 0.2032)
		(layers "F.Cu" "B.Cu")
		(net "GND")
	)
	(via
		(at 345.483434 -216.25052)
		(size 0.4572)
		(drill 0.2032)
		(layers "F.Cu" "B.Cu")
		(net "GND")
	)
	(via
		(at 93.13545 -40.310308)
		(size 0.508)
		(drill 0.254)
		(layers "F.Cu" "B.Cu")
		(net "GND")
	)
	(via
		(at 137.124694 -273.453098)
		(size 0.4318)
		(drill 0.2032)
		(layers "F.Cu" "B.Cu")
		(net "GND")
	)
	(via
		(at 225.468434 -125.670818)
		(size 0.508)
		(drill 0.254)
		(layers "F.Cu" "B.Cu")
		(net "GND")
	)
	(via
		(at 309.30088 -63.464948)
		(size 0.508)
		(drill 0.254)
		(layers "F.Cu" "B.Cu")
		(net "GND")
	)
	(via
		(at 202.971146 -270.416782)
		(size 0.4572)
		(drill 0.2032)
		(layers "F.Cu" "B.Cu")
		(net "GND")
	)
	(via
		(at 165.252146 -306.116736)
		(size 0.4572)
		(drill 0.2032)
		(layers "F.Cu" "B.Cu")
		(net "GND")
	)
	(via
		(at 429.299624 -18.235422)
		(size 0.508)
		(drill 0.254)
		(layers "F.Cu" "B.Cu")
		(net "GND")
	)
	(via
		(at 187.355734 -104.575356)
		(size 0.4572)
		(drill 0.254)
		(layers "F.Cu" "B.Cu")
		(net "GND")
	)
	(via
		(at 101.882448 -277.522432)
		(size 0.4572)
		(drill 0.2032)
		(layers "F.Cu" "B.Cu")
		(net "GND")
	)
	(via
		(at 409.748482 -284.866588)
		(size 0.4572)
		(drill 0.2032)
		(layers "F.Cu" "B.Cu")
		(net "GND")
	)
	(via
		(at 246.942356 -36.040314)
		(size 0.508)
		(drill 0.254)
		(layers "F.Cu" "B.Cu")
		(net "GND")
	)
	(via
		(at 357.23068 -238.225584)
		(size 0.4572)
		(drill 0.2032)
		(layers "F.Cu" "B.Cu")
		(net "GND")
	)
	(via
		(at 259.06349 -52.441602)
		(size 0.508)
		(drill 0.254)
		(layers "F.Cu" "B.Cu")
		(net "GND")
	)
	(via
		(at 123.387866 -217.064336)
		(size 0.4572)
		(drill 0.2032)
		(layers "F.Cu" "B.Cu")
		(net "GND")
	)
	(via
		(at 52.795424 -174.356522)
		(size 0.49022)
		(drill 0.254)
		(layers "F.Cu" "B.Cu")
		(net "GND")
	)
	(via
		(at 47.21733 -393.315698)
		(size 0.508)
		(drill 0.254)
		(layers "F.Cu" "B.Cu")
		(net "GND")
	)
	(via
		(at 63.250064 -431.451258)
		(size 0.4572)
		(drill 0.2032)
		(layers "F.Cu" "B.Cu")
		(net "GND")
	)
	(via
		(at 116.762784 -297.19778)
		(size 0.508)
		(drill 0.254)
		(layers "F.Cu" "B.Cu")
		(net "GND")
	)
	(via
		(at 129.136394 -284.033722)
		(size 0.4572)
		(drill 0.2032)
		(layers "F.Cu" "B.Cu")
		(net "GND")
	)
	(via
		(at 372.26748 -236.597952)
		(size 0.4572)
		(drill 0.2032)
		(layers "F.Cu" "B.Cu")
		(net "GND")
	)
	(via
		(at 324.6882 -20.632928)
		(size 0.508)
		(drill 0.254)
		(layers "F.Cu" "B.Cu")
		(net "GND")
	)
	(via
		(at 345.483434 -222.761556)
		(size 0.4572)
		(drill 0.2032)
		(layers "F.Cu" "B.Cu")
		(net "GND")
	)
	(via
		(at 457.221082 -222.816674)
		(size 0.4572)
		(drill 0.2032)
		(layers "F.Cu" "B.Cu")
		(net "GND")
	)
	(via
		(at 347.184472 -37.424614)
		(size 0.49022)
		(drill 0.254)
		(layers "F.Cu" "B.Cu")
		(net "GND")
	)
	(via
		(at 411.168596 -19.125438)
		(size 0.508)
		(drill 0.254)
		(layers "F.Cu" "B.Cu")
		(net "GND")
	)
	(via
		(at 35.976814 -194.766692)
		(size 0.4572)
		(drill 0.2032)
		(layers "F.Cu" "B.Cu")
		(net "GND")
	)
	(via
		(at 7.035546 -290.816792)
		(size 0.4572)
		(drill 0.2032)
		(layers "F.Cu" "B.Cu")
		(net "GND")
	)
	(via
		(at 191.296798 -194.72275)
		(size 0.508)
		(drill 0.254)
		(layers "F.Cu" "B.Cu")
		(net "GND")
	)
	(via
		(at 161.808414 -245.76659)
		(size 0.4572)
		(drill 0.2032)
		(layers "F.Cu" "B.Cu")
		(net "GND")
	)
	(via
		(at 84.179918 -403.883876)
		(size 0.4064)
		(drill 0.2032)
		(layers "F.Cu" "B.Cu")
		(net "GND")
	)
	(via
		(at 366.13846 -56.911748)
		(size 0.508)
		(drill 0.254)
		(layers "F.Cu" "B.Cu")
		(net "GND")
	)
	(via
		(at 274.163282 -264.466578)
		(size 0.4572)
		(drill 0.2032)
		(layers "F.Cu" "B.Cu")
		(net "GND")
	)
	(via
		(at 341.39632 -331.703426)
		(size 0.508)
		(drill 0.254)
		(layers "F.Cu" "B.Cu")
		(net "GND")
	)
	(via
		(at 417.173918 -400.224244)
		(size 0.4572)
		(drill 0.254)
		(layers "F.Cu" "B.Cu")
		(net "GND")
	)
	(via
		(at 56.398414 -232.166668)
		(size 0.4572)
		(drill 0.2032)
		(layers "F.Cu" "B.Cu")
		(net "GND")
	)
	(via
		(at 414.659064 -362.649262)
		(size 0.49022)
		(drill 0.254)
		(layers "F.Cu" "B.Cu")
		(net "GND")
	)
	(via
		(at 384.955034 -230.900478)
		(size 0.4318)
		(drill 0.2032)
		(layers "F.Cu" "B.Cu")
		(net "GND")
	)
	(via
		(at 373.830342 -410.664152)
		(size 0.4572)
		(drill 0.254)
		(layers "F.Cu" "B.Cu")
		(net "GND")
	)
	(via
		(at 143.34998 -431.451258)
		(size 0.4572)
		(drill 0.2032)
		(layers "F.Cu" "B.Cu")
		(net "GND")
	)
	(via
		(at 161.808414 -194.766692)
		(size 0.4572)
		(drill 0.2032)
		(layers "F.Cu" "B.Cu")
		(net "GND")
	)
	(via
		(at 294.904414 -229.616762)
		(size 0.4572)
		(drill 0.2032)
		(layers "F.Cu" "B.Cu")
		(net "GND")
	)
	(via
		(at 246.150892 -135.92302)
		(size 0.508)
		(drill 0.254)
		(layers "F.Cu" "B.Cu")
		(net "GND")
	)
	(via
		(at 460.664814 -197.316598)
		(size 0.4572)
		(drill 0.2032)
		(layers "F.Cu" "B.Cu")
		(net "GND")
	)
	(via
		(at 457.5683 -387.30682)
		(size 0.508)
		(drill 0.254)
		(layers "F.Cu" "B.Cu")
		(net "GND")
	)
	(via
		(at 68.76669 -407.638504)
		(size 0.4572)
		(drill 0.254)
		(layers "F.Cu" "B.Cu")
		(net "GND")
	)
	(via
		(at 121.148348 -276.708616)
		(size 0.4572)
		(drill 0.2032)
		(layers "F.Cu" "B.Cu")
		(net "GND")
	)
	(via
		(at 103.71455 -262.120634)
		(size 0.4572)
		(drill 0.2032)
		(layers "F.Cu" "B.Cu")
		(net "GND")
	)
	(via
		(at 425.96689 -10.16508)
		(size 0.508)
		(drill 0.254)
		(layers "F.Cu" "B.Cu")
		(net "GND")
	)
	(via
		(at 345.48318 -235.783882)
		(size 0.4572)
		(drill 0.2032)
		(layers "F.Cu" "B.Cu")
		(net "GND")
	)
	(via
		(at 126.350014 -435.0512)
		(size 0.4572)
		(drill 0.2032)
		(layers "F.Cu" "B.Cu")
		(net "GND")
	)
	(via
		(at 125.737112 -240.667286)
		(size 0.4572)
		(drill 0.2032)
		(layers "F.Cu" "B.Cu")
		(net "GND")
	)
	(via
		(at 303.322482 -424.033188)
		(size 0.508)
		(drill 0.254)
		(layers "F.Cu" "B.Cu")
		(net "GND")
	)
	(via
		(at 230.225092 -135.47852)
		(size 0.508)
		(drill 0.254)
		(layers "F.Cu" "B.Cu")
		(net "GND")
	)
	(via
		(at 289.206686 -12.544552)
		(size 0.508)
		(drill 0.254)
		(layers "F.Cu" "B.Cu")
		(net "GND")
	)
	(via
		(at 455.011282 -213.46668)
		(size 0.4572)
		(drill 0.2032)
		(layers "F.Cu" "B.Cu")
		(net "GND")
	)
	(via
		(at 413.74949 -400.858228)
		(size 0.4064)
		(drill 0.2032)
		(layers "F.Cu" "B.Cu")
		(net "GND")
	)
	(via
		(at 342.303862 -284.033722)
		(size 0.4572)
		(drill 0.2032)
		(layers "F.Cu" "B.Cu")
		(net "GND")
	)
	(via
		(at 157.499304 -206.666592)
		(size 0.4572)
		(drill 0.2032)
		(layers "F.Cu" "B.Cu")
		(net "GND")
	)
	(via
		(at 386.004562 -281.59202)
		(size 0.4572)
		(drill 0.2032)
		(layers "F.Cu" "B.Cu")
		(net "GND")
	)
	(via
		(at 340.894162 -257.175254)
		(size 0.4572)
		(drill 0.2032)
		(layers "F.Cu" "B.Cu")
		(net "GND")
	)
	(via
		(at 53.811678 -410.030168)
		(size 0.4064)
		(drill 0.2032)
		(layers "F.Cu" "B.Cu")
		(net "GND")
	)
	(via
		(at 182.42788 -98.643948)
		(size 0.508)
		(drill 0.254)
		(layers "F.Cu" "B.Cu")
		(net "GND")
	)
	(via
		(at 428.279814 -267.016738)
		(size 0.4572)
		(drill 0.2032)
		(layers "F.Cu" "B.Cu")
		(net "GND")
	)
	(via
		(at 383.545334 -238.225584)
		(size 0.4572)
		(drill 0.2032)
		(layers "F.Cu" "B.Cu")
		(net "GND")
	)
	(via
		(at 159.918146 -199.01662)
		(size 0.4572)
		(drill 0.2032)
		(layers "F.Cu" "B.Cu")
		(net "GND")
	)
	(via
		(at 126.316994 -284.033722)
		(size 0.4572)
		(drill 0.2032)
		(layers "F.Cu" "B.Cu")
		(net "GND")
	)
	(via
		(at 363.809534 -226.831144)
		(size 0.4572)
		(drill 0.2032)
		(layers "F.Cu" "B.Cu")
		(net "GND")
	)
	(via
		(at 59.250072 -427.851316)
		(size 0.4572)
		(drill 0.2032)
		(layers "F.Cu" "B.Cu")
		(net "GND")
	)
	(via
		(at 128.35001 -437.34736)
		(size 0.4572)
		(drill 0.2032)
		(layers "F.Cu" "B.Cu")
		(net "GND")
	)
	(via
		(at 54.724046 -217.716608)
		(size 0.4572)
		(drill 0.2032)
		(layers "F.Cu" "B.Cu")
		(net "GND")
	)
	(via
		(at 442.133482 -198.166736)
		(size 0.4572)
		(drill 0.2032)
		(layers "F.Cu" "B.Cu")
		(net "GND")
	)
	(via
		(at 383.478278 -400.224244)
		(size 0.4572)
		(drill 0.254)
		(layers "F.Cu" "B.Cu")
		(net "GND")
	)
	(via
		(at 234.544362 -249.765058)
		(size 0.508)
		(drill 0.254)
		(layers "F.Cu" "B.Cu")
		(net "GND")
	)
	(via
		(at 59.842146 -315.46673)
		(size 0.4572)
		(drill 0.2032)
		(layers "F.Cu" "B.Cu")
		(net "GND")
	)
	(via
		(at 123.027694 -253.919736)
		(size 0.4572)
		(drill 0.2032)
		(layers "F.Cu" "B.Cu")
		(net "GND")
	)
	(via
		(at 257.185414 -313.766708)
		(size 0.4572)
		(drill 0.2032)
		(layers "F.Cu" "B.Cu")
		(net "GND")
	)
	(via
		(at 202.971146 -281.466798)
		(size 0.4572)
		(drill 0.2032)
		(layers "F.Cu" "B.Cu")
		(net "GND")
	)
	(via
		(at 88.145366 -219.506038)
		(size 0.4572)
		(drill 0.2032)
		(layers "F.Cu" "B.Cu")
		(net "GND")
	)
	(via
		(at 73.417938 -193.10223)
		(size 0.508)
		(drill 0.254)
		(layers "F.Cu" "B.Cu")
		(net "GND")
	)
	(via
		(at 345.013534 -249.620024)
		(size 0.4572)
		(drill 0.2032)
		(layers "F.Cu" "B.Cu")
		(net "GND")
	)
	(via
		(at 259.98932 -422.9608)
		(size 0.508)
		(drill 0.254)
		(layers "F.Cu" "B.Cu")
		(net "GND")
	)
	(via
		(at 65.25006 -438.499758)
		(size 0.4572)
		(drill 0.2032)
		(layers "F.Cu" "B.Cu")
		(net "GND")
	)
	(via
		(at 312.611008 -400.858228)
		(size 0.4064)
		(drill 0.2032)
		(layers "F.Cu" "B.Cu")
		(net "GND")
	)
	(via
		(at 283.916882 -205.816708)
		(size 0.4572)
		(drill 0.2032)
		(layers "F.Cu" "B.Cu")
		(net "GND")
	)
	(via
		(at 339.987636 -335.129124)
		(size 0.508)
		(drill 0.254)
		(layers "F.Cu" "B.Cu")
		(net "GND")
	)
	(via
		(at 277.607014 -233.016806)
		(size 0.4572)
		(drill 0.2032)
		(layers "F.Cu" "B.Cu")
		(net "GND")
	)
	(via
		(at 269.234412 -71.95185)
		(size 0.6604)
		(drill 0.3302)
		(layers "F.Cu" "B.Cu")
		(net "GND")
	)
	(via
		(at 207.071214 -295.916604)
		(size 0.4572)
		(drill 0.2032)
		(layers "F.Cu" "B.Cu")
		(net "GND")
	)
	(via
		(at 365.044228 -329.943714)
		(size 0.508)
		(drill 0.254)
		(layers "F.Cu" "B.Cu")
		(net "GND")
	)
	(via
		(at 450.911214 -311.216802)
		(size 0.4572)
		(drill 0.2032)
		(layers "F.Cu" "B.Cu")
		(net "GND")
	)
	(via
		(at 122.447812 -247.992138)
		(size 0.4572)
		(drill 0.2032)
		(layers "F.Cu" "B.Cu")
		(net "GND")
	)
	(via
		(at 372.26748 -243.108988)
		(size 0.4572)
		(drill 0.2032)
		(layers "F.Cu" "B.Cu")
		(net "GND")
	)
	(via
		(at 171.765214 -294.216582)
		(size 0.4572)
		(drill 0.2032)
		(layers "F.Cu" "B.Cu")
		(net "GND")
	)
	(via
		(at 464.764882 -312.91657)
		(size 0.4572)
		(drill 0.2032)
		(layers "F.Cu" "B.Cu")
		(net "GND")
	)
	(via
		(at 165.905942 -404.51786)
		(size 0.4572)
		(drill 0.254)
		(layers "F.Cu" "B.Cu")
		(net "GND")
	)
	(via
		(at 432.379882 -289.966654)
		(size 0.4572)
		(drill 0.2032)
		(layers "F.Cu" "B.Cu")
		(net "GND")
	)
	(via
		(at 376.966734 -236.597952)
		(size 0.4572)
		(drill 0.2032)
		(layers "F.Cu" "B.Cu")
		(net "GND")
	)
	(via
		(at 176.896014 -294.216582)
		(size 0.4572)
		(drill 0.2032)
		(layers "F.Cu" "B.Cu")
		(net "GND")
	)
	(via
		(at 277.607014 -279.766776)
		(size 0.4572)
		(drill 0.2032)
		(layers "F.Cu" "B.Cu")
		(net "GND")
	)
	(via
		(at 102.73665 -394.322808)
		(size 0.508)
		(drill 0.254)
		(layers "F.Cu" "B.Cu")
		(net "GND")
	)
	(via
		(at 197.28942 -29.839666)
		(size 0.508)
		(drill 0.254)
		(layers "F.Cu" "B.Cu")
		(net "GND")
	)
	(via
		(at 92.954348 -275.08073)
		(size 0.4572)
		(drill 0.2032)
		(layers "F.Cu" "B.Cu")
		(net "GND")
	)
	(via
		(at 464.764882 -310.366664)
		(size 0.4572)
		(drill 0.2032)
		(layers "F.Cu" "B.Cu")
		(net "GND")
	)
	(via
		(at 353.111816 -288.103056)
		(size 0.4572)
		(drill 0.2032)
		(layers "F.Cu" "B.Cu")
		(net "GND")
	)
	(via
		(at 173.755558 -105.375456)
		(size 0.4572)
		(drill 0.254)
		(layers "F.Cu" "B.Cu")
		(net "GND")
	)
	(via
		(at 86.375494 -281.59202)
		(size 0.4572)
		(drill 0.2032)
		(layers "F.Cu" "B.Cu")
		(net "GND")
	)
	(via
		(at 59.250072 -429.147224)
		(size 0.4572)
		(drill 0.2032)
		(layers "F.Cu" "B.Cu")
		(net "GND")
	)
	(via
		(at 453.121014 -229.616762)
		(size 0.4572)
		(drill 0.2032)
		(layers "F.Cu" "B.Cu")
		(net "GND")
	)
	(via
		(at 376.136662 -257.98907)
		(size 0.4572)
		(drill 0.2032)
		(layers "F.Cu" "B.Cu")
		(net "GND")
	)
	(via
		(at 381.19558 -232.528364)
		(size 0.4572)
		(drill 0.2032)
		(layers "F.Cu" "B.Cu")
		(net "GND")
	)
	(via
		(at 136.946894 -14.705076)
		(size 0.508)
		(drill 0.254)
		(layers "F.Cu" "B.Cu")
		(net "GND")
	)
	(via
		(at 62.051946 -301.866808)
		(size 0.4572)
		(drill 0.2032)
		(layers "F.Cu" "B.Cu")
		(net "GND")
	)
	(via
		(at 2.764536 -356.030022)
		(size 0.508)
		(drill 0.254)
		(layers "F.Cu" "B.Cu")
		(net "GND")
	)
	(via
		(at 424.836082 -215.166702)
		(size 0.4572)
		(drill 0.2032)
		(layers "F.Cu" "B.Cu")
		(net "GND")
	)
	(via
		(at 303.782476 -401.492212)
		(size 0.4572)
		(drill 0.254)
		(layers "F.Cu" "B.Cu")
		(net "GND")
	)
	(via
		(at 48.854614 -239.81664)
		(size 0.4572)
		(drill 0.2032)
		(layers "F.Cu" "B.Cu")
		(net "GND")
	)
	(via
		(at 453.81926 -59.634628)
		(size 0.508)
		(drill 0.254)
		(layers "F.Cu" "B.Cu")
		(net "GND")
	)
	(via
		(at 35.976814 -308.666642)
		(size 0.4572)
		(drill 0.2032)
		(layers "F.Cu" "B.Cu")
		(net "GND")
	)
	(via
		(at 438.033414 -278.066754)
		(size 0.4572)
		(drill 0.2032)
		(layers "F.Cu" "B.Cu")
		(net "GND")
	)
	(via
		(at 438.045352 -319.319656)
		(size 0.4572)
		(drill 0.2032)
		(layers "F.Cu" "B.Cu")
		(net "GND")
	)
	(via
		(at 105.92054 -111.595408)
		(size 0.508)
		(drill 0.254)
		(layers "F.Cu" "B.Cu")
		(net "GND")
	)
	(via
		(at 130.767074 -403.883876)
		(size 0.4064)
		(drill 0.2032)
		(layers "F.Cu" "B.Cu")
		(net "GND")
	)
	(via
		(at 16.789146 -301.866808)
		(size 0.4572)
		(drill 0.2032)
		(layers "F.Cu" "B.Cu")
		(net "GND")
	)
	(via
		(at 191.19088 -14.986508)
		(size 0.508)
		(drill 0.254)
		(layers "F.Cu" "B.Cu")
		(net "GND")
	)
	(via
		(at 462.555082 -239.81664)
		(size 0.4572)
		(drill 0.2032)
		(layers "F.Cu" "B.Cu")
		(net "GND")
	)
	(via
		(at 391.397998 -146.436588)
		(size 0.508)
		(drill 0.254)
		(layers "F.Cu" "B.Cu")
		(net "GND")
	)
	(via
		(at 424.836082 -306.96662)
		(size 0.4572)
		(drill 0.2032)
		(layers "F.Cu" "B.Cu")
		(net "GND")
	)
	(via
		(at 234.79252 -387.37794)
		(size 0.508)
		(drill 0.254)
		(layers "F.Cu" "B.Cu")
		(net "GND")
	)
	(via
		(at 264.729214 -298.466764)
		(size 0.4572)
		(drill 0.2032)
		(layers "F.Cu" "B.Cu")
		(net "GND")
	)
	(via
		(at 336.195162 -257.175254)
		(size 0.4572)
		(drill 0.2032)
		(layers "F.Cu" "B.Cu")
		(net "GND")
	)
	(via
		(at 334.25003 -437.34736)
		(size 0.4572)
		(drill 0.2032)
		(layers "F.Cu" "B.Cu")
		(net "GND")
	)
	(via
		(at 379.426216 -283.219906)
		(size 0.4572)
		(drill 0.2032)
		(layers "F.Cu" "B.Cu")
		(net "GND")
	)
	(via
		(at 113.629694 -275.08073)
		(size 0.4572)
		(drill 0.2032)
		(layers "F.Cu" "B.Cu")
		(net "GND")
	)
	(via
		(at 112.626902 -332.56601)
		(size 0.49022)
		(drill 0.254)
		(layers "F.Cu" "B.Cu")
		(net "GND")
	)
	(via
		(at 104.275128 -297.077638)
		(size 0.508)
		(drill 0.254)
		(layers "F.Cu" "B.Cu")
		(net "GND")
	)
	(via
		(at 379.316234 -226.017328)
		(size 0.4572)
		(drill 0.2032)
		(layers "F.Cu" "B.Cu")
		(net "GND")
	)
	(via
		(at 336.316574 -75.32116)
		(size 0.508)
		(drill 0.254)
		(layers "F.Cu" "B.Cu")
		(net "GND")
	)
	(via
		(at 353.581462 -277.522432)
		(size 0.4572)
		(drill 0.2032)
		(layers "F.Cu" "B.Cu")
		(net "GND")
	)
	(via
		(at 33.767014 -241.516662)
		(size 0.4572)
		(drill 0.2032)
		(layers "F.Cu" "B.Cu")
		(net "GND")
	)
	(via
		(at 411.958282 -244.066568)
		(size 0.4572)
		(drill 0.2032)
		(layers "F.Cu" "B.Cu")
		(net "GND")
	)
	(via
		(at 116.449094 -275.08073)
		(size 0.4572)
		(drill 0.2032)
		(layers "F.Cu" "B.Cu")
		(net "GND")
	)
	(via
		(at 91.704922 -333.833724)
		(size 0.508)
		(drill 0.254)
		(layers "F.Cu" "B.Cu")
		(net "GND")
	)
	(via
		(at 393.805918 -171.96943)
		(size 0.508)
		(drill 0.254)
		(layers "F.Cu" "B.Cu")
		(net "GND")
	)
	(via
		(at 127.256794 -279.150318)
		(size 0.4572)
		(drill 0.2032)
		(layers "F.Cu" "B.Cu")
		(net "GND")
	)
	(via
		(at 95.303594 -287.28924)
		(size 0.4572)
		(drill 0.2032)
		(layers "F.Cu" "B.Cu")
		(net "GND")
	)
	(via
		(at 132.350002 -438.499758)
		(size 0.4572)
		(drill 0.2032)
		(layers "F.Cu" "B.Cu")
		(net "GND")
	)
	(via
		(at 362.14558 -414.978088)
		(size 0.508)
		(drill 0.254)
		(layers "F.Cu" "B.Cu")
		(net "GND")
	)
	(via
		(at 98.123248 -264.50036)
		(size 0.4572)
		(drill 0.2032)
		(layers "F.Cu" "B.Cu")
		(net "GND")
	)
	(via
		(at 366.372902 -250.337066)
		(size 0.4572)
		(drill 0.2032)
		(layers "F.Cu" "B.Cu")
		(net "GND")
	)
	(via
		(at 383.655062 -264.50036)
		(size 0.4572)
		(drill 0.2032)
		(layers "F.Cu" "B.Cu")
		(net "GND")
	)
	(via
		(at 379.769116 -335.1911)
		(size 0.49022)
		(drill 0.254)
		(layers "F.Cu" "B.Cu")
		(net "GND")
	)
	(via
		(at 61.212222 -150.93188)
		(size 0.508)
		(drill 0.254)
		(layers "F.Cu" "B.Cu")
		(net "GND")
	)
	(via
		(at 45.890688 -351.227898)
		(size 0.508)
		(drill 0.254)
		(layers "F.Cu" "B.Cu")
		(net "GND")
	)
	(via
		(at 256.750312 -78.694788)
		(size 0.508)
		(drill 0.254)
		(layers "F.Cu" "B.Cu")
		(net "GND")
	)
	(via
		(at 195.427346 -231.316784)
		(size 0.4572)
		(drill 0.2032)
		(layers "F.Cu" "B.Cu")
		(net "GND")
	)
	(via
		(at 339.209888 -42.811446)
		(size 0.4572)
		(drill 0.2032)
		(layers "F.Cu" "B.Cu")
		(net "GND")
	)
	(via
		(at 132.785866 -247.992138)
		(size 0.4572)
		(drill 0.2032)
		(layers "F.Cu" "B.Cu")
		(net "GND")
	)
	(via
		(at 361.929934 -226.831144)
		(size 0.4572)
		(drill 0.2032)
		(layers "F.Cu" "B.Cu")
		(net "GND")
	)
	(via
		(at 88.615012 -217.064336)
		(size 0.4572)
		(drill 0.2032)
		(layers "F.Cu" "B.Cu")
		(net "GND")
	)
	(via
		(at 383.478278 -401.492212)
		(size 0.4572)
		(drill 0.254)
		(layers "F.Cu" "B.Cu")
		(net "GND")
	)
	(via
		(at 339.014562 -289.807142)
		(size 0.4572)
		(drill 0.2032)
		(layers "F.Cu" "B.Cu")
		(net "GND")
	)
	(via
		(at 272.273014 -201.56678)
		(size 0.4572)
		(drill 0.2032)
		(layers "F.Cu" "B.Cu")
		(net "GND")
	)
	(via
		(at 0.76454 -77.040232)
		(size 0.508)
		(drill 0.254)
		(layers "F.Cu" "B.Cu")
		(net "GND")
	)
	(via
		(at 179.105814 -284.866588)
		(size 0.4572)
		(drill 0.2032)
		(layers "F.Cu" "B.Cu")
		(net "GND")
	)
	(via
		(at 44.754546 -315.46673)
		(size 0.4572)
		(drill 0.2032)
		(layers "F.Cu" "B.Cu")
		(net "GND")
	)
	(via
		(at 423.17162 -208.366614)
		(size 0.4572)
		(drill 0.2032)
		(layers "F.Cu" "B.Cu")
		(net "GND")
	)
	(via
		(at 388.349998 -432.451256)
		(size 0.4572)
		(drill 0.2032)
		(layers "F.Cu" "B.Cu")
		(net "GND")
	)
	(via
		(at 187.883546 -220.266768)
		(size 0.4572)
		(drill 0.2032)
		(layers "F.Cu" "B.Cu")
		(net "GND")
	)
	(via
		(at 194.193414 -250.866656)
		(size 0.4572)
		(drill 0.2032)
		(layers "F.Cu" "B.Cu")
		(net "GND")
	)
	(via
		(at 382.35001 -425.547282)
		(size 0.4572)
		(drill 0.2032)
		(layers "F.Cu" "B.Cu")
		(net "GND")
	)
	(via
		(at 405.90597 -407.00452)
		(size 0.4064)
		(drill 0.2032)
		(layers "F.Cu" "B.Cu")
		(net "GND")
	)
	(via
		(at 381.775462 -279.150318)
		(size 0.4572)
		(drill 0.2032)
		(layers "F.Cu" "B.Cu")
		(net "GND")
	)
	(via
		(at 409.748482 -269.566644)
		(size 0.4572)
		(drill 0.2032)
		(layers "F.Cu" "B.Cu")
		(net "GND")
	)
	(via
		(at 173.755558 -121.375424)
		(size 0.4572)
		(drill 0.254)
		(layers "F.Cu" "B.Cu")
		(net "GND")
	)
	(via
		(at 438.033414 -315.46673)
		(size 0.4572)
		(drill 0.2032)
		(layers "F.Cu" "B.Cu")
		(net "GND")
	)
	(via
		(at 31.876746 -221.96679)
		(size 0.4572)
		(drill 0.2032)
		(layers "F.Cu" "B.Cu")
		(net "GND")
	)
	(via
		(at 48.020732 -0.76454)
		(size 0.508)
		(drill 0.254)
		(layers "F.Cu" "B.Cu")
		(net "GND")
	)
	(via
		(at 299.004482 -267.866622)
		(size 0.4572)
		(drill 0.2032)
		(layers "F.Cu" "B.Cu")
		(net "GND")
	)
	(via
		(at 299.004482 -280.61666)
		(size 0.4572)
		(drill 0.2032)
		(layers "F.Cu" "B.Cu")
		(net "GND")
	)
	(via
		(at 88.615012 -239.853216)
		(size 0.4572)
		(drill 0.2032)
		(layers "F.Cu" "B.Cu")
		(net "GND")
	)
	(via
		(at 457.221082 -211.766658)
		(size 0.4572)
		(drill 0.2032)
		(layers "F.Cu" "B.Cu")
		(net "GND")
	)
	(via
		(at 25.39492 -428.081948)
		(size 0.508)
		(drill 0.254)
		(layers "F.Cu" "B.Cu")
		(net "GND")
	)
	(via
		(at 453.121014 -290.816792)
		(size 0.4572)
		(drill 0.2032)
		(layers "F.Cu" "B.Cu")
		(net "GND")
	)
	(via
		(at 296.794682 -213.46668)
		(size 0.4572)
		(drill 0.2032)
		(layers "F.Cu" "B.Cu")
		(net "GND")
	)
	(via
		(at 368.916204 -255.53035)
		(size 0.4572)
		(drill 0.2032)
		(layers "F.Cu" "B.Cu")
		(net "GND")
	)
	(via
		(at 443.367414 -281.466798)
		(size 0.4572)
		(drill 0.2032)
		(layers "F.Cu" "B.Cu")
		(net "GND")
	)
	(via
		(at 9.245346 -242.3668)
		(size 0.4572)
		(drill 0.2032)
		(layers "F.Cu" "B.Cu")
		(net "GND")
	)
	(via
		(at 272.273014 -204.96657)
		(size 0.4572)
		(drill 0.2032)
		(layers "F.Cu" "B.Cu")
		(net "GND")
	)
	(via
		(at 270.063214 -268.71676)
		(size 0.4572)
		(drill 0.2032)
		(layers "F.Cu" "B.Cu")
		(net "GND")
	)
	(via
		(at 35.976814 -249.166634)
		(size 0.4572)
		(drill 0.2032)
		(layers "F.Cu" "B.Cu")
		(net "GND")
	)
	(via
		(at 37.940234 -110.587282)
		(size 0.508)
		(drill 0.254)
		(layers "F.Cu" "B.Cu")
		(net "GND")
	)
	(via
		(at 343.604596 -400.224244)
		(size 0.4572)
		(drill 0.254)
		(layers "F.Cu" "B.Cu")
		(net "GND")
	)
	(via
		(at 73.273158 -407.00452)
		(size 0.4064)
		(drill 0.2032)
		(layers "F.Cu" "B.Cu")
		(net "GND")
	)
	(via
		(at 109.760766 -219.506038)
		(size 0.4572)
		(drill 0.2032)
		(layers "F.Cu" "B.Cu")
		(net "GND")
	)
	(via
		(at 161.808414 -305.266598)
		(size 0.4572)
		(drill 0.2032)
		(layers "F.Cu" "B.Cu")
		(net "GND")
	)
	(via
		(at 186.568842 -25.084532)
		(size 0.508)
		(drill 0.254)
		(layers "F.Cu" "B.Cu")
		(net "GND")
	)
	(via
		(at 184.142126 -345.648788)
		(size 0.508)
		(drill 0.254)
		(layers "F.Cu" "B.Cu")
		(net "GND")
	)
	(via
		(at 296.794682 -224.516696)
		(size 0.4572)
		(drill 0.2032)
		(layers "F.Cu" "B.Cu")
		(net "GND")
	)
	(via
		(at 98.122994 -274.266914)
		(size 0.4572)
		(drill 0.2032)
		(layers "F.Cu" "B.Cu")
		(net "GND")
	)
	(via
		(at 460.664814 -289.11677)
		(size 0.4572)
		(drill 0.2032)
		(layers "F.Cu" "B.Cu")
		(net "GND")
	)
	(via
		(at 201.737214 -207.51673)
		(size 0.4572)
		(drill 0.2032)
		(layers "F.Cu" "B.Cu")
		(net "GND")
	)
	(via
		(at 120.36298 -128.681988)
		(size 0.508)
		(drill 0.254)
		(layers "F.Cu" "B.Cu")
		(net "GND")
	)
	(via
		(at 457.221082 -295.916604)
		(size 0.4572)
		(drill 0.2032)
		(layers "F.Cu" "B.Cu")
		(net "GND")
	)
	(via
		(at 141.302994 -407.00452)
		(size 0.4064)
		(drill 0.2032)
		(layers "F.Cu" "B.Cu")
		(net "GND")
	)
	(via
		(at 412.676086 -165.727126)
		(size 0.508)
		(drill 0.254)
		(layers "F.Cu" "B.Cu")
		(net "GND")
	)
	(via
		(at 349.369888 -403.883876)
		(size 0.4064)
		(drill 0.2032)
		(layers "F.Cu" "B.Cu")
		(net "GND")
	)
	(via
		(at 195.427346 -279.766776)
		(size 0.4572)
		(drill 0.2032)
		(layers "F.Cu" "B.Cu")
		(net "GND")
	)
	(via
		(at 458.455014 -287.416748)
		(size 0.4572)
		(drill 0.2032)
		(layers "F.Cu" "B.Cu")
		(net "GND")
	)
	(via
		(at 202.971146 -279.766776)
		(size 0.4572)
		(drill 0.2032)
		(layers "F.Cu" "B.Cu")
		(net "GND")
	)
	(via
		(at 37.210746 -273.816572)
		(size 0.4572)
		(drill 0.2032)
		(layers "F.Cu" "B.Cu")
		(net "GND")
	)
	(via
		(at 314.307982 -272.966688)
		(size 0.4572)
		(drill 0.2032)
		(layers "F.Cu" "B.Cu")
		(net "GND")
	)
	(via
		(at 306.548282 -295.916604)
		(size 0.4572)
		(drill 0.2032)
		(layers "F.Cu" "B.Cu")
		(net "GND")
	)
	(via
		(at 342.774016 -266.941808)
		(size 0.4572)
		(drill 0.2032)
		(layers "F.Cu" "B.Cu")
		(net "GND")
	)
	(via
		(at 344.07348 -230.086662)
		(size 0.4572)
		(drill 0.2032)
		(layers "F.Cu" "B.Cu")
		(net "GND")
	)
	(via
		(at 136.075166 -243.922804)
		(size 0.4572)
		(drill 0.2032)
		(layers "F.Cu" "B.Cu")
		(net "GND")
	)
	(via
		(at 277.607014 -265.316716)
		(size 0.4572)
		(drill 0.2032)
		(layers "F.Cu" "B.Cu")
		(net "GND")
	)
	(via
		(at 187.883546 -304.416714)
		(size 0.4572)
		(drill 0.2032)
		(layers "F.Cu" "B.Cu")
		(net "GND")
	)
	(via
		(at 134.02183 -336.823304)
		(size 0.508)
		(drill 0.254)
		(layers "F.Cu" "B.Cu")
		(net "GND")
	)
	(via
		(at 256.667 -67.782948)
		(size 0.508)
		(drill 0.254)
		(layers "F.Cu" "B.Cu")
		(net "GND")
	)
	(via
		(at 411.958282 -297.616626)
		(size 0.4572)
		(drill 0.2032)
		(layers "F.Cu" "B.Cu")
		(net "GND")
	)
	(via
		(at 411.349952 -433.899564)
		(size 0.4572)
		(drill 0.2032)
		(layers "F.Cu" "B.Cu")
		(net "GND")
	)
	(via
		(at 335.05775 -75.32116)
		(size 0.508)
		(drill 0.254)
		(layers "F.Cu" "B.Cu")
		(net "GND")
	)
	(via
		(at 415.295588 -18.491454)
		(size 0.508)
		(drill 0.254)
		(layers "F.Cu" "B.Cu")
		(net "GND")
	)
	(via
		(at 268.829282 -232.166668)
		(size 0.4572)
		(drill 0.2032)
		(layers "F.Cu" "B.Cu")
		(net "GND")
	)
	(via
		(at 90.024712 -247.178322)
		(size 0.4572)
		(drill 0.2032)
		(layers "F.Cu" "B.Cu")
		(net "GND")
	)
	(via
		(at 93.784166 -237.411514)
		(size 0.4572)
		(drill 0.2032)
		(layers "F.Cu" "B.Cu")
		(net "GND")
	)
	(via
		(at 230.984044 -53.364892)
		(size 0.508)
		(drill 0.254)
		(layers "F.Cu" "B.Cu")
		(net "GND")
	)
	(via
		(at 201.592942 -130.266948)
		(size 0.508)
		(drill 0.254)
		(layers "F.Cu" "B.Cu")
		(net "GND")
	)
	(via
		(at 344.183462 -259.616956)
		(size 0.4572)
		(drill 0.2032)
		(layers "F.Cu" "B.Cu")
		(net "GND")
	)
	(via
		(at 132.425948 -273.453098)
		(size 0.4572)
		(drill 0.2032)
		(layers "F.Cu" "B.Cu")
		(net "GND")
	)
	(via
		(at 111.640366 -219.506038)
		(size 0.4572)
		(drill 0.2032)
		(layers "F.Cu" "B.Cu")
		(net "GND")
	)
	(via
		(at 157.000956 -319.65138)
		(size 0.508)
		(drill 0.254)
		(layers "F.Cu" "B.Cu")
		(net "GND")
	)
	(via
		(at 177.068988 -414.697418)
		(size 0.508)
		(drill 0.254)
		(layers "F.Cu" "B.Cu")
		(net "GND")
	)
	(via
		(at 181.07152 -353.19335)
		(size 0.49022)
		(drill 0.254)
		(layers "F.Cu" "B.Cu")
		(net "GND")
	)
	(via
		(at 197.637146 -197.316598)
		(size 0.4572)
		(drill 0.2032)
		(layers "F.Cu" "B.Cu")
		(net "GND")
	)
	(via
		(at 376.496834 -242.294918)
		(size 0.4572)
		(drill 0.2032)
		(layers "F.Cu" "B.Cu")
		(net "GND")
	)
	(via
		(at 428.279814 -242.3668)
		(size 0.4572)
		(drill 0.2032)
		(layers "F.Cu" "B.Cu")
		(net "GND")
	)
	(via
		(at 268.829282 -310.366664)
		(size 0.4572)
		(drill 0.2032)
		(layers "F.Cu" "B.Cu")
		(net "GND")
	)
	(via
		(at 285.413196 -360.054144)
		(size 0.508)
		(drill 0.254)
		(layers "F.Cu" "B.Cu")
		(net "GND")
	)
	(via
		(at 66.152014 -249.166634)
		(size 0.4572)
		(drill 0.2032)
		(layers "F.Cu" "B.Cu")
		(net "GND")
	)
	(via
		(at 58.608214 -266.1666)
		(size 0.4572)
		(drill 0.2032)
		(layers "F.Cu" "B.Cu")
		(net "GND")
	)
	(via
		(at 53.45049 -407.638504)
		(size 0.4572)
		(drill 0.254)
		(layers "F.Cu" "B.Cu")
		(net "GND")
	)
	(via
		(at 439.923682 -272.966688)
		(size 0.4572)
		(drill 0.2032)
		(layers "F.Cu" "B.Cu")
		(net "GND")
	)
	(via
		(at 449.677282 -301.01667)
		(size 0.4572)
		(drill 0.2032)
		(layers "F.Cu" "B.Cu")
		(net "GND")
	)
	(via
		(at 136.48944 -30.612588)
		(size 0.508)
		(drill 0.254)
		(layers "F.Cu" "B.Cu")
		(net "GND")
	)
	(via
		(at 356.373684 -248.42089)
		(size 0.4572)
		(drill 0.2032)
		(layers "F.Cu" "B.Cu")
		(net "GND")
	)
	(via
		(at 20.889214 -294.216582)
		(size 0.4572)
		(drill 0.2032)
		(layers "F.Cu" "B.Cu")
		(net "GND")
	)
	(via
		(at 136.654794 -269.38351)
		(size 0.4318)
		(drill 0.2032)
		(layers "F.Cu" "B.Cu")
		(net "GND")
	)
	(via
		(at 149.349968 -427.699678)
		(size 0.4572)
		(drill 0.2032)
		(layers "F.Cu" "B.Cu")
		(net "GND")
	)
	(via
		(at 446.920366 -73.625456)
		(size 0.508)
		(drill 0.254)
		(layers "F.Cu" "B.Cu")
		(net "GND")
	)
	(via
		(at 2.764536 -366.190022)
		(size 0.508)
		(drill 0.254)
		(layers "F.Cu" "B.Cu")
		(net "GND")
	)
	(via
		(at 334.455516 -68.184268)
		(size 0.6604)
		(drill 0.3302)
		(layers "F.Cu" "B.Cu")
		(net "GND")
	)
	(via
		(at 338.250022 -438.499758)
		(size 0.4572)
		(drill 0.2032)
		(layers "F.Cu" "B.Cu")
		(net "GND")
	)
	(via
		(at 153.88082 -102.306628)
		(size 0.508)
		(drill 0.254)
		(layers "F.Cu" "B.Cu")
		(net "GND")
	)
	(via
		(at 272.273014 -234.716574)
		(size 0.4572)
		(drill 0.2032)
		(layers "F.Cu" "B.Cu")
		(net "GND")
	)
	(via
		(at 129.235708 -358.75468)
		(size 0.508)
		(drill 0.254)
		(layers "F.Cu" "B.Cu")
		(net "GND")
	)
	(via
		(at 390.349994 -433.899564)
		(size 0.4572)
		(drill 0.2032)
		(layers "F.Cu" "B.Cu")
		(net "GND")
	)
	(via
		(at 336.250026 -436.347362)
		(size 0.4572)
		(drill 0.2032)
		(layers "F.Cu" "B.Cu")
		(net "GND")
	)
	(via
		(at 341.254334 -213.732618)
		(size 0.4572)
		(drill 0.2032)
		(layers "F.Cu" "B.Cu")
		(net "GND")
	)
	(via
		(at 16.789146 -201.56678)
		(size 0.4572)
		(drill 0.2032)
		(layers "F.Cu" "B.Cu")
		(net "GND")
	)
	(via
		(at 65.800478 -400.858228)
		(size 0.4064)
		(drill 0.2032)
		(layers "F.Cu" "B.Cu")
		(net "GND")
	)
	(via
		(at 424.836082 -211.766658)
		(size 0.4572)
		(drill 0.2032)
		(layers "F.Cu" "B.Cu")
		(net "GND")
	)
	(via
		(at 462.264506 -45.019722)
		(size 0.508)
		(drill 0.254)
		(layers "F.Cu" "B.Cu")
		(net "GND")
	)
	(via
		(at 376.96648 -233.34218)
		(size 0.4572)
		(drill 0.2032)
		(layers "F.Cu" "B.Cu")
		(net "GND")
	)
	(via
		(at 342.824816 -36.92779)
		(size 0.49022)
		(drill 0.254)
		(layers "F.Cu" "B.Cu")
		(net "GND")
	)
	(via
		(at 166.26713 -12.495022)
		(size 0.508)
		(drill 0.254)
		(layers "F.Cu" "B.Cu")
		(net "GND")
	)
	(via
		(at 202.971146 -225.36658)
		(size 0.4572)
		(drill 0.2032)
		(layers "F.Cu" "B.Cu")
		(net "GND")
	)
	(via
		(at 20.889214 -226.216718)
		(size 0.4572)
		(drill 0.2032)
		(layers "F.Cu" "B.Cu")
		(net "GND")
	)
	(via
		(at 380.725934 -228.45903)
		(size 0.4572)
		(drill 0.2032)
		(layers "F.Cu" "B.Cu")
		(net "GND")
	)
	(via
		(at 407.525982 -409.396184)
		(size 0.4572)
		(drill 0.254)
		(layers "F.Cu" "B.Cu")
		(net "GND")
	)
	(via
		(at 182.549546 -292.516814)
		(size 0.4572)
		(drill 0.2032)
		(layers "F.Cu" "B.Cu")
		(net "GND")
	)
	(via
		(at 14.579346 -289.11677)
		(size 0.4572)
		(drill 0.2032)
		(layers "F.Cu" "B.Cu")
		(net "GND")
	)
	(via
		(at 442.270388 -38.487858)
		(size 0.508)
		(drill 0.254)
		(layers "F.Cu" "B.Cu")
		(net "GND")
	)
	(via
		(at 356.401116 -274.266914)
		(size 0.4572)
		(drill 0.2032)
		(layers "F.Cu" "B.Cu")
		(net "GND")
	)
	(via
		(at 376.479054 -357.998268)
		(size 0.508)
		(drill 0.254)
		(layers "F.Cu" "B.Cu")
		(net "GND")
	)
	(via
		(at 135.94588 -97.422208)
		(size 0.508)
		(drill 0.254)
		(layers "F.Cu" "B.Cu")
		(net "GND")
	)
	(via
		(at 443.73038 -368.775488)
		(size 0.49022)
		(drill 0.254)
		(layers "F.Cu" "B.Cu")
		(net "GND")
	)
	(via
		(at 369.427506 -182.463948)
		(size 0.508)
		(drill 0.254)
		(layers "F.Cu" "B.Cu")
		(net "GND")
	)
	(via
		(at 309.992014 -309.51678)
		(size 0.4572)
		(drill 0.2032)
		(layers "F.Cu" "B.Cu")
		(net "GND")
	)
	(via
		(at 471.03538 -48.864266)
		(size 0.508)
		(drill 0.254)
		(layers "F.Cu" "B.Cu")
		(net "GND")
	)
	(via
		(at 95.303594 -267.755878)
		(size 0.4572)
		(drill 0.2032)
		(layers "F.Cu" "B.Cu")
		(net "GND")
	)
	(via
		(at 296.794682 -289.966654)
		(size 0.4572)
		(drill 0.2032)
		(layers "F.Cu" "B.Cu")
		(net "GND")
	)
	(via
		(at 353.795584 -246.669306)
		(size 0.4572)
		(drill 0.2032)
		(layers "F.Cu" "B.Cu")
		(net "GND")
	)
	(via
		(at 138.34999 -432.747166)
		(size 0.4572)
		(drill 0.2032)
		(layers "F.Cu" "B.Cu")
		(net "GND")
	)
	(via
		(at 361.460034 -234.15625)
		(size 0.4572)
		(drill 0.2032)
		(layers "F.Cu" "B.Cu")
		(net "GND")
	)
	(via
		(at 457.221082 -219.41663)
		(size 0.4572)
		(drill 0.2032)
		(layers "F.Cu" "B.Cu")
		(net "GND")
	)
	(via
		(at 93.894148 -275.08073)
		(size 0.4572)
		(drill 0.2032)
		(layers "F.Cu" "B.Cu")
		(net "GND")
	)
	(via
		(at 126.786894 -289.807142)
		(size 0.4572)
		(drill 0.2032)
		(layers "F.Cu" "B.Cu")
		(net "GND")
	)
	(via
		(at 348.302834 -237.411514)
		(size 0.4572)
		(drill 0.2032)
		(layers "F.Cu" "B.Cu")
		(net "GND")
	)
	(via
		(at 279.816814 -216.016586)
		(size 0.4572)
		(drill 0.2032)
		(layers "F.Cu" "B.Cu")
		(net "GND")
	)
	(via
		(at 98.122994 -271.011396)
		(size 0.4572)
		(drill 0.2032)
		(layers "F.Cu" "B.Cu")
		(net "GND")
	)
	(via
		(at 264.729214 -242.3668)
		(size 0.4572)
		(drill 0.2032)
		(layers "F.Cu" "B.Cu")
		(net "GND")
	)
	(via
		(at 23.67788 -6.090412)
		(size 0.508)
		(drill 0.254)
		(layers "F.Cu" "B.Cu")
		(net "GND")
	)
	(via
		(at 283.916882 -198.166736)
		(size 0.4572)
		(drill 0.2032)
		(layers "F.Cu" "B.Cu")
		(net "GND")
	)
	(via
		(at 73.420732 -0.76454)
		(size 0.508)
		(drill 0.254)
		(layers "F.Cu" "B.Cu")
		(net "GND")
	)
	(via
		(at 447.449448 -176.694592)
		(size 0.508)
		(drill 0.254)
		(layers "F.Cu" "B.Cu")
		(net "GND")
	)
	(via
		(at 179.105814 -249.166634)
		(size 0.4572)
		(drill 0.2032)
		(layers "F.Cu" "B.Cu")
		(net "GND")
	)
	(via
		(at 188.93028 -103.698548)
		(size 0.508)
		(drill 0.254)
		(layers "F.Cu" "B.Cu")
		(net "GND")
	)
	(via
		(at 129.496566 -219.506038)
		(size 0.4572)
		(drill 0.2032)
		(layers "F.Cu" "B.Cu")
		(net "GND")
	)
	(via
		(at 439.923682 -275.516594)
		(size 0.4572)
		(drill 0.2032)
		(layers "F.Cu" "B.Cu")
		(net "GND")
	)
	(via
		(at 449.677282 -289.966654)
		(size 0.4572)
		(drill 0.2032)
		(layers "F.Cu" "B.Cu")
		(net "GND")
	)
	(via
		(at 428.279814 -296.766742)
		(size 0.4572)
		(drill 0.2032)
		(layers "F.Cu" "B.Cu")
		(net "GND")
	)
	(via
		(at 180.211222 -355.538278)
		(size 0.49022)
		(drill 0.254)
		(layers "F.Cu" "B.Cu")
		(net "GND")
	)
	(via
		(at 455.011282 -299.316648)
		(size 0.4572)
		(drill 0.2032)
		(layers "F.Cu" "B.Cu")
		(net "GND")
	)
	(via
		(at 276.373082 -277.216616)
		(size 0.4572)
		(drill 0.2032)
		(layers "F.Cu" "B.Cu")
		(net "GND")
	)
	(via
		(at 281.707082 -244.066568)
		(size 0.4572)
		(drill 0.2032)
		(layers "F.Cu" "B.Cu")
		(net "GND")
	)
	(via
		(at 300.238414 -251.716794)
		(size 0.4572)
		(drill 0.2032)
		(layers "F.Cu" "B.Cu")
		(net "GND")
	)
	(via
		(at 14.579346 -265.316716)
		(size 0.4572)
		(drill 0.2032)
		(layers "F.Cu" "B.Cu")
		(net "GND")
	)
	(via
		(at 42.057066 -10.16508)
		(size 0.508)
		(drill 0.254)
		(layers "F.Cu" "B.Cu")
		(net "GND")
	)
	(via
		(at 406.267158 -409.396184)
		(size 0.4572)
		(drill 0.254)
		(layers "F.Cu" "B.Cu")
		(net "GND")
	)
	(via
		(at 359.580434 -216.25052)
		(size 0.4572)
		(drill 0.2032)
		(layers "F.Cu" "B.Cu")
		(net "GND")
	)
	(via
		(at 262.519414 -300.166786)
		(size 0.4572)
		(drill 0.2032)
		(layers "F.Cu" "B.Cu")
		(net "GND")
	)
	(via
		(at 97.653348 -268.569694)
		(size 0.4572)
		(drill 0.2032)
		(layers "F.Cu" "B.Cu")
		(net "GND")
	)
	(via
		(at 374.19153 -407.00452)
		(size 0.4064)
		(drill 0.2032)
		(layers "F.Cu" "B.Cu")
		(net "GND")
	)
	(via
		(at 56.744362 -151.59228)
		(size 0.508)
		(drill 0.254)
		(layers "F.Cu" "B.Cu")
		(net "GND")
	)
	(via
		(at 137.878566 -409.396184)
		(size 0.4572)
		(drill 0.254)
		(layers "F.Cu" "B.Cu")
		(net "GND")
	)
	(via
		(at 221.48292 -50.673)
		(size 0.508)
		(drill 0.254)
		(layers "F.Cu" "B.Cu")
		(net "GND")
	)
	(via
		(at 217.090498 -193.46799)
		(size 0.508)
		(drill 0.254)
		(layers "F.Cu" "B.Cu")
		(net "GND")
	)
	(via
		(at 56.83885 -155.125674)
		(size 0.49022)
		(drill 0.254)
		(layers "F.Cu" "B.Cu")
		(net "GND")
	)
	(via
		(at 53.682392 -174.062898)
		(size 0.508)
		(drill 0.254)
		(layers "F.Cu" "B.Cu")
		(net "GND")
	)
	(via
		(at 279.816814 -290.816792)
		(size 0.4572)
		(drill 0.2032)
		(layers "F.Cu" "B.Cu")
		(net "GND")
	)
	(via
		(at 380.725934 -217.064336)
		(size 0.4572)
		(drill 0.2032)
		(layers "F.Cu" "B.Cu")
		(net "GND")
	)
	(via
		(at 348.148148 -331.71892)
		(size 0.508)
		(drill 0.254)
		(layers "F.Cu" "B.Cu")
		(net "GND")
	)
	(via
		(at 342.303862 -259.616956)
		(size 0.4572)
		(drill 0.2032)
		(layers "F.Cu" "B.Cu")
		(net "GND")
	)
	(via
		(at 281.707082 -278.916638)
		(size 0.4572)
		(drill 0.2032)
		(layers "F.Cu" "B.Cu")
		(net "GND")
	)
	(via
		(at 130.546094 -286.475424)
		(size 0.4572)
		(drill 0.2032)
		(layers "F.Cu" "B.Cu")
		(net "GND")
	)
	(via
		(at 261.163308 -68.616068)
		(size 0.508)
		(drill 0.254)
		(layers "F.Cu" "B.Cu")
		(net "GND")
	)
	(via
		(at 59.673998 -403.883876)
		(size 0.4064)
		(drill 0.2032)
		(layers "F.Cu" "B.Cu")
		(net "GND")
	)
	(via
		(at 383.11709 -403.883876)
		(size 0.4064)
		(drill 0.2032)
		(layers "F.Cu" "B.Cu")
		(net "GND")
	)
	(via
		(at 347.363034 -234.15625)
		(size 0.4572)
		(drill 0.2032)
		(layers "F.Cu" "B.Cu")
		(net "GND")
	)
	(via
		(at 427.045882 -224.516696)
		(size 0.4572)
		(drill 0.2032)
		(layers "F.Cu" "B.Cu")
		(net "GND")
	)
	(via
		(at 425.591986 -364.071662)
		(size 0.49022)
		(drill 0.254)
		(layers "F.Cu" "B.Cu")
		(net "GND")
	)
	(via
		(at 88.724994 -287.28924)
		(size 0.4572)
		(drill 0.2032)
		(layers "F.Cu" "B.Cu")
		(net "GND")
	)
	(via
		(at 264.729214 -204.96657)
		(size 0.4572)
		(drill 0.2032)
		(layers "F.Cu" "B.Cu")
		(net "GND")
	)
	(via
		(at 378.84608 -243.108988)
		(size 0.4572)
		(drill 0.2032)
		(layers "F.Cu" "B.Cu")
		(net "GND")
	)
	(via
		(at 216.824814 -235.566712)
		(size 0.4572)
		(drill 0.2032)
		(layers "F.Cu" "B.Cu")
		(net "GND")
	)
	(via
		(at 384.955034 -248.806208)
		(size 0.4318)
		(drill 0.2032)
		(layers "F.Cu" "B.Cu")
		(net "GND")
	)
	(via
		(at 268.829282 -215.166702)
		(size 0.4572)
		(drill 0.2032)
		(layers "F.Cu" "B.Cu")
		(net "GND")
	)
	(via
		(at 125.737366 -230.900478)
		(size 0.4572)
		(drill 0.2032)
		(layers "F.Cu" "B.Cu")
		(net "GND")
	)
	(via
		(at 317.250064 -436.051198)
		(size 0.4572)
		(drill 0.2032)
		(layers "F.Cu" "B.Cu")
		(net "GND")
	)
	(via
		(at 376.606816 -260.430772)
		(size 0.4572)
		(drill 0.2032)
		(layers "F.Cu" "B.Cu")
		(net "GND")
	)
	(via
		(at 62.051946 -251.716794)
		(size 0.4572)
		(drill 0.2032)
		(layers "F.Cu" "B.Cu")
		(net "GND")
	)
	(via
		(at 377.839732 -77.712824)
		(size 0.508)
		(drill 0.254)
		(layers "F.Cu" "B.Cu")
		(net "GND")
	)
	(via
		(at 44.754546 -223.666558)
		(size 0.4572)
		(drill 0.2032)
		(layers "F.Cu" "B.Cu")
		(net "GND")
	)
	(via
		(at 407.858214 -278.066754)
		(size 0.4572)
		(drill 0.2032)
		(layers "F.Cu" "B.Cu")
		(net "GND")
	)
	(via
		(at 448.74815 -71.877174)
		(size 0.508)
		(drill 0.254)
		(layers "F.Cu" "B.Cu")
		(net "GND")
	)
	(via
		(at 24.332946 -289.11677)
		(size 0.4572)
		(drill 0.2032)
		(layers "F.Cu" "B.Cu")
		(net "GND")
	)
	(via
		(at 414.110678 -403.249892)
		(size 0.4572)
		(drill 0.254)
		(layers "F.Cu" "B.Cu")
		(net "GND")
	)
	(via
		(at 137.722102 -335.957672)
		(size 0.508)
		(drill 0.254)
		(layers "F.Cu" "B.Cu")
		(net "GND")
	)
	(via
		(at 100.30714 -414.620456)
		(size 0.508)
		(drill 0.254)
		(layers "F.Cu" "B.Cu")
		(net "GND")
	)
	(via
		(at 254.975614 -229.616762)
		(size 0.4572)
		(drill 0.2032)
		(layers "F.Cu" "B.Cu")
		(net "GND")
	)
	(via
		(at 453.0852 -58.867548)
		(size 0.508)
		(drill 0.254)
		(layers "F.Cu" "B.Cu")
		(net "GND")
	)
	(via
		(at 337.135216 -255.547622)
		(size 0.4572)
		(drill 0.2032)
		(layers "F.Cu" "B.Cu")
		(net "GND")
	)
	(via
		(at 415.402014 -212.616796)
		(size 0.4572)
		(drill 0.2032)
		(layers "F.Cu" "B.Cu")
		(net "GND")
	)
	(via
		(at 223.759522 -71.970138)
		(size 0.508)
		(drill 0.254)
		(layers "F.Cu" "B.Cu")
		(net "GND")
	)
	(via
		(at 384.124962 -268.569694)
		(size 0.4572)
		(drill 0.2032)
		(layers "F.Cu" "B.Cu")
		(net "GND")
	)
	(via
		(at 405.648414 -315.46673)
		(size 0.4572)
		(drill 0.2032)
		(layers "F.Cu" "B.Cu")
		(net "GND")
	)
	(via
		(at 291.460682 -280.61666)
		(size 0.4572)
		(drill 0.2032)
		(layers "F.Cu" "B.Cu")
		(net "GND")
	)
	(via
		(at 88.196166 -336.765392)
		(size 0.49022)
		(drill 0.254)
		(layers "F.Cu" "B.Cu")
		(net "GND")
	)
	(via
		(at 31.876746 -201.56678)
		(size 0.4572)
		(drill 0.2032)
		(layers "F.Cu" "B.Cu")
		(net "GND")
	)
	(via
		(at 122.087894 -278.336502)
		(size 0.4572)
		(drill 0.2032)
		(layers "F.Cu" "B.Cu")
		(net "GND")
	)
	(via
		(at 355.821234 -216.25052)
		(size 0.4572)
		(drill 0.2032)
		(layers "F.Cu" "B.Cu")
		(net "GND")
	)
	(via
		(at 176.901348 -352.074988)
		(size 0.508)
		(drill 0.254)
		(layers "F.Cu" "B.Cu")
		(net "GND")
	)
	(via
		(at 216.6112 -73.294748)
		(size 0.508)
		(drill 0.254)
		(layers "F.Cu" "B.Cu")
		(net "GND")
	)
	(via
		(at 23.041102 -404.842218)
		(size 0.508)
		(drill 0.254)
		(layers "F.Cu" "B.Cu")
		(net "GND")
	)
	(via
		(at 54.3814 -174.593504)
		(size 0.508)
		(drill 0.254)
		(layers "F.Cu" "B.Cu")
		(net "GND")
	)
	(via
		(at 415.605214 -273.816572)
		(size 0.4572)
		(drill 0.2032)
		(layers "F.Cu" "B.Cu")
		(net "GND")
	)
	(via
		(at 143.34998 -432.747166)
		(size 0.4572)
		(drill 0.2032)
		(layers "F.Cu" "B.Cu")
		(net "GND")
	)
	(via
		(at 428.279814 -273.816572)
		(size 0.4572)
		(drill 0.2032)
		(layers "F.Cu" "B.Cu")
		(net "GND")
	)
	(via
		(at 355.931216 -276.708616)
		(size 0.4572)
		(drill 0.2032)
		(layers "F.Cu" "B.Cu")
		(net "GND")
	)
	(via
		(at 336.250026 -430.299622)
		(size 0.4572)
		(drill 0.2032)
		(layers "F.Cu" "B.Cu")
		(net "GND")
	)
	(via
		(at 384.826764 -333.453232)
		(size 0.508)
		(drill 0.254)
		(layers "F.Cu" "B.Cu")
		(net "GND")
	)
	(via
		(at 43.520614 -284.866588)
		(size 0.4572)
		(drill 0.2032)
		(layers "F.Cu" "B.Cu")
		(net "GND")
	)
	(via
		(at 174.2059 -353.201478)
		(size 0.49022)
		(drill 0.254)
		(layers "F.Cu" "B.Cu")
		(net "GND")
	)
	(via
		(at 88.86317 -400.224244)
		(size 0.4572)
		(drill 0.254)
		(layers "F.Cu" "B.Cu")
		(net "GND")
	)
	(via
		(at 194.193414 -316.316614)
		(size 0.4572)
		(drill 0.2032)
		(layers "F.Cu" "B.Cu")
		(net "GND")
	)
	(via
		(at 100.832412 -238.225584)
		(size 0.4572)
		(drill 0.2032)
		(layers "F.Cu" "B.Cu")
		(net "GND")
	)
	(via
		(at 7.035546 -261.916672)
		(size 0.4572)
		(drill 0.2032)
		(layers "F.Cu" "B.Cu")
		(net "GND")
	)
	(via
		(at 432.379882 -271.266666)
		(size 0.4572)
		(drill 0.2032)
		(layers "F.Cu" "B.Cu")
		(net "GND")
	)
	(via
		(at 299.004482 -291.666676)
		(size 0.4572)
		(drill 0.2032)
		(layers "F.Cu" "B.Cu")
		(net "GND")
	)
	(via
		(at 9.245346 -220.266768)
		(size 0.4572)
		(drill 0.2032)
		(layers "F.Cu" "B.Cu")
		(net "GND")
	)
	(via
		(at 16.789146 -313.766708)
		(size 0.4572)
		(drill 0.2032)
		(layers "F.Cu" "B.Cu")
		(net "GND")
	)
	(via
		(at 194.193414 -261.066788)
		(size 0.4572)
		(drill 0.2032)
		(layers "F.Cu" "B.Cu")
		(net "GND")
	)
	(via
		(at 415.402014 -270.416782)
		(size 0.4572)
		(drill 0.2032)
		(layers "F.Cu" "B.Cu")
		(net "GND")
	)
	(via
		(at 261.389876 -97.29978)
		(size 0.508)
		(drill 0.254)
		(layers "F.Cu" "B.Cu")
		(net "GND")
	)
	(via
		(at 403.813772 -18.491454)
		(size 0.508)
		(drill 0.254)
		(layers "F.Cu" "B.Cu")
		(net "GND")
	)
	(via
		(at 171.0182 -53.678328)
		(size 0.508)
		(drill 0.254)
		(layers "F.Cu" "B.Cu")
		(net "GND")
	)
	(via
		(at 424.836082 -233.86669)
		(size 0.4572)
		(drill 0.2032)
		(layers "F.Cu" "B.Cu")
		(net "GND")
	)
	(via
		(at 256.51333 -48.859186)
		(size 0.508)
		(drill 0.254)
		(layers "F.Cu" "B.Cu")
		(net "GND")
	)
	(via
		(at 295.86682 -417.990528)
		(size 0.508)
		(drill 0.254)
		(layers "F.Cu" "B.Cu")
		(net "GND")
	)
	(via
		(at 7.495286 -101.125528)
		(size 0.508)
		(drill 0.254)
		(layers "F.Cu" "B.Cu")
		(net "GND")
	)
	(via
		(at 189.368684 -323.434456)
		(size 0.4572)
		(drill 0.2032)
		(layers "F.Cu" "B.Cu")
		(net "GND")
	)
	(via
		(at 352.641662 -266.128246)
		(size 0.4572)
		(drill 0.2032)
		(layers "F.Cu" "B.Cu")
		(net "GND")
	)
	(via
		(at 136.532366 -404.51786)
		(size 0.4572)
		(drill 0.254)
		(layers "F.Cu" "B.Cu")
		(net "GND")
	)
	(via
		(at 372.26748 -238.225584)
		(size 0.4572)
		(drill 0.2032)
		(layers "F.Cu" "B.Cu")
		(net "GND")
	)
	(via
		(at 292.694614 -195.616576)
		(size 0.4572)
		(drill 0.2032)
		(layers "F.Cu" "B.Cu")
		(net "GND")
	)
	(via
		(at 419.502082 -213.46668)
		(size 0.4572)
		(drill 0.2032)
		(layers "F.Cu" "B.Cu")
		(net "GND")
	)
	(via
		(at 422.945814 -267.016738)
		(size 0.4572)
		(drill 0.2032)
		(layers "F.Cu" "B.Cu")
		(net "GND")
	)
	(via
		(at 424.836082 -299.316648)
		(size 0.4572)
		(drill 0.2032)
		(layers "F.Cu" "B.Cu")
		(net "GND")
	)
	(via
		(at 181.113684 -323.434456)
		(size 0.4572)
		(drill 0.2032)
		(layers "F.Cu" "B.Cu")
		(net "GND")
	)
	(via
		(at 84.855812 -226.831144)
		(size 0.4572)
		(drill 0.2032)
		(layers "F.Cu" "B.Cu")
		(net "GND")
	)
	(via
		(at 296.794682 -239.81664)
		(size 0.4572)
		(drill 0.2032)
		(layers "F.Cu" "B.Cu")
		(net "GND")
	)
	(via
		(at 373.979694 -335.89976)
		(size 0.508)
		(drill 0.254)
		(layers "F.Cu" "B.Cu")
		(net "GND")
	)
	(via
		(at 67.250056 -437.49976)
		(size 0.4572)
		(drill 0.2032)
		(layers "F.Cu" "B.Cu")
		(net "GND")
	)
	(via
		(at 339.84438 -227.64496)
		(size 0.4572)
		(drill 0.2032)
		(layers "F.Cu" "B.Cu")
		(net "GND")
	)
	(via
		(at 212.724746 -265.316716)
		(size 0.4572)
		(drill 0.2032)
		(layers "F.Cu" "B.Cu")
		(net "GND")
	)
	(via
		(at 457.221082 -200.716642)
		(size 0.4572)
		(drill 0.2032)
		(layers "F.Cu" "B.Cu")
		(net "GND")
	)
	(via
		(at 169.352214 -241.516662)
		(size 0.4572)
		(drill 0.2032)
		(layers "F.Cu" "B.Cu")
		(net "GND")
	)
	(via
		(at 344.363294 -43.281092)
		(size 0.4572)
		(drill 0.2032)
		(layers "F.Cu" "B.Cu")
		(net "GND")
	)
	(via
		(at 182.549546 -267.016738)
		(size 0.4572)
		(drill 0.2032)
		(layers "F.Cu" "B.Cu")
		(net "GND")
	)
	(via
		(at 62.051946 -216.016586)
		(size 0.4572)
		(drill 0.2032)
		(layers "F.Cu" "B.Cu")
		(net "GND")
	)
	(via
		(at 369.387628 -331.776832)
		(size 0.49022)
		(drill 0.254)
		(layers "F.Cu" "B.Cu")
		(net "GND")
	)
	(via
		(at 99.422712 -227.64496)
		(size 0.4572)
		(drill 0.2032)
		(layers "F.Cu" "B.Cu")
		(net "GND")
	)
	(via
		(at 53.908706 -403.249892)
		(size 0.4572)
		(drill 0.254)
		(layers "F.Cu" "B.Cu")
		(net "GND")
	)
	(via
		(at 52.298346 -223.666558)
		(size 0.4572)
		(drill 0.2032)
		(layers "F.Cu" "B.Cu")
		(net "GND")
	)
	(via
		(at 280.532078 -425.57446)
		(size 0.508)
		(drill 0.254)
		(layers "F.Cu" "B.Cu")
		(net "GND")
	)
	(via
		(at 205.180946 -216.016586)
		(size 0.4572)
		(drill 0.2032)
		(layers "F.Cu" "B.Cu")
		(net "GND")
	)
	(via
		(at 13.345414 -196.466714)
		(size 0.4572)
		(drill 0.2032)
		(layers "F.Cu" "B.Cu")
		(net "GND")
	)
	(via
		(at 113.629948 -258.803394)
		(size 0.4572)
		(drill 0.2032)
		(layers "F.Cu" "B.Cu")
		(net "GND")
	)
	(via
		(at 127.616966 -226.017328)
		(size 0.4572)
		(drill 0.2032)
		(layers "F.Cu" "B.Cu")
		(net "GND")
	)
	(via
		(at 175.005746 -195.616576)
		(size 0.4572)
		(drill 0.2032)
		(layers "F.Cu" "B.Cu")
		(net "GND")
	)
	(via
		(at 29.666946 -231.316784)
		(size 0.4572)
		(drill 0.2032)
		(layers "F.Cu" "B.Cu")
		(net "GND")
	)
	(via
		(at 382.245362 -278.336502)
		(size 0.4572)
		(drill 0.2032)
		(layers "F.Cu" "B.Cu")
		(net "GND")
	)
	(via
		(at 328.288396 -401.492212)
		(size 0.4572)
		(drill 0.254)
		(layers "F.Cu" "B.Cu")
		(net "GND")
	)
	(via
		(at 264.729214 -267.016738)
		(size 0.4572)
		(drill 0.2032)
		(layers "F.Cu" "B.Cu")
		(net "GND")
	)
	(via
		(at 261.285482 -216.866724)
		(size 0.4572)
		(drill 0.2032)
		(layers "F.Cu" "B.Cu")
		(net "GND")
	)
	(via
		(at 430.489614 -204.96657)
		(size 0.4572)
		(drill 0.2032)
		(layers "F.Cu" "B.Cu")
		(net "GND")
	)
	(via
		(at 298.442888 -361.625388)
		(size 0.49022)
		(drill 0.254)
		(layers "F.Cu" "B.Cu")
		(net "GND")
	)
	(via
		(at 356.62616 -329.119738)
		(size 0.508)
		(drill 0.254)
		(layers "F.Cu" "B.Cu")
		(net "GND")
	)
	(via
		(at 384.124962 -255.547622)
		(size 0.4318)
		(drill 0.2032)
		(layers "F.Cu" "B.Cu")
		(net "GND")
	)
	(via
		(at 14.579346 -206.666592)
		(size 0.4572)
		(drill 0.2032)
		(layers "F.Cu" "B.Cu")
		(net "GND")
	)
	(via
		(at 56.049672 -165.082474)
		(size 0.49022)
		(drill 0.254)
		(layers "F.Cu" "B.Cu")
		(net "GND")
	)
	(via
		(at 344.183462 -269.38351)
		(size 0.4572)
		(drill 0.2032)
		(layers "F.Cu" "B.Cu")
		(net "GND")
	)
	(via
		(at 384.485134 -220.319854)
		(size 0.4572)
		(drill 0.2032)
		(layers "F.Cu" "B.Cu")
		(net "GND")
	)
	(via
		(at 277.607014 -301.866808)
		(size 0.4572)
		(drill 0.2032)
		(layers "F.Cu" "B.Cu")
		(net "GND")
	)
	(via
		(at 310.207914 -220.266768)
		(size 0.4572)
		(drill 0.2032)
		(layers "F.Cu" "B.Cu")
		(net "GND")
	)
	(via
		(at 389.50773 -407.00452)
		(size 0.4064)
		(drill 0.2032)
		(layers "F.Cu" "B.Cu")
		(net "GND")
	)
	(via
		(at 83.54441 -338.303616)
		(size 0.508)
		(drill 0.254)
		(layers "F.Cu" "B.Cu")
		(net "GND")
	)
	(via
		(at 191.983614 -219.41663)
		(size 0.4572)
		(drill 0.2032)
		(layers "F.Cu" "B.Cu")
		(net "GND")
	)
	(via
		(at 462.555082 -210.066636)
		(size 0.4572)
		(drill 0.2032)
		(layers "F.Cu" "B.Cu")
		(net "GND")
	)
	(via
		(at 86.845394 -259.616956)
		(size 0.4318)
		(drill 0.2032)
		(layers "F.Cu" "B.Cu")
		(net "GND")
	)
	(via
		(at 211.99729 -130.923538)
		(size 0.508)
		(drill 0.254)
		(layers "F.Cu" "B.Cu")
		(net "GND")
	)
	(via
		(at 167.461946 -225.36658)
		(size 0.4572)
		(drill 0.2032)
		(layers "F.Cu" "B.Cu")
		(net "GND")
	)
	(via
		(at 64.23533 -441.225432)
		(size 0.508)
		(drill 0.254)
		(layers "F.Cu" "B.Cu")
		(net "GND")
	)
	(via
		(at 171.11726 -50.970688)
		(size 0.508)
		(drill 0.254)
		(layers "F.Cu" "B.Cu")
		(net "GND")
	)
	(via
		(at 132.895594 -275.8948)
		(size 0.4572)
		(drill 0.2032)
		(layers "F.Cu" "B.Cu")
		(net "GND")
	)
	(via
		(at 106.001566 -226.017328)
		(size 0.4572)
		(drill 0.2032)
		(layers "F.Cu" "B.Cu")
		(net "GND")
	)
	(via
		(at 385.588764 -333.453232)
		(size 0.508)
		(drill 0.254)
		(layers "F.Cu" "B.Cu")
		(net "GND")
	)
	(via
		(at 361.460034 -240.667286)
		(size 0.4572)
		(drill 0.2032)
		(layers "F.Cu" "B.Cu")
		(net "GND")
	)
	(via
		(at 164.018214 -239.81664)
		(size 0.4572)
		(drill 0.2032)
		(layers "F.Cu" "B.Cu")
		(net "GND")
	)
	(via
		(at 427.045882 -205.816708)
		(size 0.4572)
		(drill 0.2032)
		(layers "F.Cu" "B.Cu")
		(net "GND")
	)
	(via
		(at 102.712266 -220.319854)
		(size 0.4572)
		(drill 0.2032)
		(layers "F.Cu" "B.Cu")
		(net "GND")
	)
	(via
		(at 45.348906 -17.61236)
		(size 0.508)
		(drill 0.254)
		(layers "F.Cu" "B.Cu")
		(net "GND")
	)
	(via
		(at 414.478724 -156.610304)
		(size 0.508)
		(drill 0.254)
		(layers "F.Cu" "B.Cu")
		(net "GND")
	)
	(via
		(at 83.097878 -403.883876)
		(size 0.4064)
		(drill 0.2032)
		(layers "F.Cu" "B.Cu")
		(net "GND")
	)
	(via
		(at 125.525022 -139.813538)
		(size 0.508)
		(drill 0.254)
		(layers "F.Cu" "B.Cu")
		(net "GND")
	)
	(via
		(at 309.992014 -263.616694)
		(size 0.4572)
		(drill 0.2032)
		(layers "F.Cu" "B.Cu")
		(net "GND")
	)
	(via
		(at 16.789146 -281.466798)
		(size 0.4572)
		(drill 0.2032)
		(layers "F.Cu" "B.Cu")
		(net "GND")
	)
	(via
		(at 261.285482 -222.816674)
		(size 0.4572)
		(drill 0.2032)
		(layers "F.Cu" "B.Cu")
		(net "GND")
	)
	(via
		(at 94.363794 -274.266914)
		(size 0.4572)
		(drill 0.2032)
		(layers "F.Cu" "B.Cu")
		(net "GND")
	)
	(via
		(at 450.06641 -31.341822)
		(size 0.508)
		(drill 0.254)
		(layers "F.Cu" "B.Cu")
		(net "GND")
	)
	(via
		(at 417.997894 -163.062158)
		(size 0.49022)
		(drill 0.254)
		(layers "F.Cu" "B.Cu")
		(net "GND")
	)
	(via
		(at 380.46152 -94.757748)
		(size 0.508)
		(drill 0.254)
		(layers "F.Cu" "B.Cu")
		(net "GND")
	)
	(via
		(at 59.842146 -290.816792)
		(size 0.4572)
		(drill 0.2032)
		(layers "F.Cu" "B.Cu")
		(net "GND")
	)
	(via
		(at 334.785462 -257.98907)
		(size 0.4572)
		(drill 0.2032)
		(layers "F.Cu" "B.Cu")
		(net "GND")
	)
	(via
		(at 243.18468 -39.039546)
		(size 0.508)
		(drill 0.254)
		(layers "F.Cu" "B.Cu")
		(net "GND")
	)
	(via
		(at 281.707082 -207.51673)
		(size 0.4572)
		(drill 0.2032)
		(layers "F.Cu" "B.Cu")
		(net "GND")
	)
	(via
		(at 460.664814 -231.316784)
		(size 0.4572)
		(drill 0.2032)
		(layers "F.Cu" "B.Cu")
		(net "GND")
	)
	(via
		(at 460.664814 -279.766776)
		(size 0.4572)
		(drill 0.2032)
		(layers "F.Cu" "B.Cu")
		(net "GND")
	)
	(via
		(at 27.292554 -399.974816)
		(size 0.508)
		(drill 0.254)
		(layers "F.Cu" "B.Cu")
		(net "GND")
	)
	(via
		(at 38.729158 -6.090412)
		(size 0.508)
		(drill 0.254)
		(layers "F.Cu" "B.Cu")
		(net "GND")
	)
	(via
		(at 101.302566 -222.761556)
		(size 0.4572)
		(drill 0.2032)
		(layers "F.Cu" "B.Cu")
		(net "GND")
	)
	(via
		(at 80.25003 -432.747166)
		(size 0.4572)
		(drill 0.2032)
		(layers "F.Cu" "B.Cu")
		(net "GND")
	)
	(via
		(at 137.124694 -279.964134)
		(size 0.4572)
		(drill 0.2032)
		(layers "F.Cu" "B.Cu")
		(net "GND")
	)
	(via
		(at 153.291794 -403.883876)
		(size 0.4064)
		(drill 0.2032)
		(layers "F.Cu" "B.Cu")
		(net "GND")
	)
	(via
		(at 31.876746 -268.71676)
		(size 0.4572)
		(drill 0.2032)
		(layers "F.Cu" "B.Cu")
		(net "GND")
	)
	(via
		(at 65.25006 -436.051198)
		(size 0.4572)
		(drill 0.2032)
		(layers "F.Cu" "B.Cu")
		(net "GND")
	)
	(via
		(at 447.467482 -216.866724)
		(size 0.4572)
		(drill 0.2032)
		(layers "F.Cu" "B.Cu")
		(net "GND")
	)
	(via
		(at 447.467482 -275.516594)
		(size 0.4572)
		(drill 0.2032)
		(layers "F.Cu" "B.Cu")
		(net "GND")
	)
	(via
		(at 149.349968 -434.899562)
		(size 0.4572)
		(drill 0.2032)
		(layers "F.Cu" "B.Cu")
		(net "GND")
	)
	(via
		(at 173.569884 -323.434456)
		(size 0.4572)
		(drill 0.2032)
		(layers "F.Cu" "B.Cu")
		(net "GND")
	)
	(via
		(at 113.989866 -238.225838)
		(size 0.4572)
		(drill 0.2032)
		(layers "F.Cu" "B.Cu")
		(net "GND")
	)
	(via
		(at 52.911248 -156.23159)
		(size 0.49022)
		(drill 0.254)
		(layers "F.Cu" "B.Cu")
		(net "GND")
	)
	(via
		(at 87.205312 -242.294918)
		(size 0.4572)
		(drill 0.2032)
		(layers "F.Cu" "B.Cu")
		(net "GND")
	)
	(via
		(at 194.193414 -233.86669)
		(size 0.4572)
		(drill 0.2032)
		(layers "F.Cu" "B.Cu")
		(net "GND")
	)
	(via
		(at 212.724746 -221.96679)
		(size 0.4572)
		(drill 0.2032)
		(layers "F.Cu" "B.Cu")
		(net "GND")
	)
	(via
		(at 132.350002 -433.747164)
		(size 0.4572)
		(drill 0.2032)
		(layers "F.Cu" "B.Cu")
		(net "GND")
	)
	(via
		(at 342.66378 -248.806208)
		(size 0.4572)
		(drill 0.2032)
		(layers "F.Cu" "B.Cu")
		(net "GND")
	)
	(via
		(at 288.529268 -364.759494)
		(size 0.49022)
		(drill 0.254)
		(layers "F.Cu" "B.Cu")
		(net "GND")
	)
	(via
		(at 35.976814 -261.066788)
		(size 0.4572)
		(drill 0.2032)
		(layers "F.Cu" "B.Cu")
		(net "GND")
	)
	(via
		(at 358.280462 -277.522432)
		(size 0.4572)
		(drill 0.2032)
		(layers "F.Cu" "B.Cu")
		(net "GND")
	)
	(via
		(at 279.816814 -304.416714)
		(size 0.4572)
		(drill 0.2032)
		(layers "F.Cu" "B.Cu")
		(net "GND")
	)
	(via
		(at 113.629694 -279.964134)
		(size 0.4572)
		(drill 0.2032)
		(layers "F.Cu" "B.Cu")
		(net "GND")
	)
	(via
		(at 377.436634 -226.017328)
		(size 0.4572)
		(drill 0.2032)
		(layers "F.Cu" "B.Cu")
		(net "GND")
	)
	(via
		(at 450.911214 -197.316598)
		(size 0.4572)
		(drill 0.2032)
		(layers "F.Cu" "B.Cu")
		(net "GND")
	)
	(via
		(at 11.936476 -422.44391)
		(size 0.508)
		(drill 0.254)
		(layers "F.Cu" "B.Cu")
		(net "GND")
	)
	(via
		(at 175.005746 -301.866808)
		(size 0.4572)
		(drill 0.2032)
		(layers "F.Cu" "B.Cu")
		(net "GND")
	)
	(via
		(at 222.535496 -32.022288)
		(size 0.508)
		(drill 0.254)
		(layers "F.Cu" "B.Cu")
		(net "GND")
	)
	(via
		(at 380.445518 -74.421238)
		(size 0.6604)
		(drill 0.3302)
		(layers "F.Cu" "B.Cu")
		(net "GND")
	)
	(via
		(at 434.589682 -284.866588)
		(size 0.4572)
		(drill 0.2032)
		(layers "F.Cu" "B.Cu")
		(net "GND")
	)
	(via
		(at 271.200372 -73.279)
		(size 0.508)
		(drill 0.254)
		(layers "F.Cu" "B.Cu")
		(net "GND")
	)
	(via
		(at 353.11588 -126.426468)
		(size 0.508)
		(drill 0.254)
		(layers "F.Cu" "B.Cu")
		(net "GND")
	)
	(via
		(at 66.152014 -211.766658)
		(size 0.4572)
		(drill 0.2032)
		(layers "F.Cu" "B.Cu")
		(net "GND")
	)
	(via
		(at 417.289742 -152.706324)
		(size 0.508)
		(drill 0.254)
		(layers "F.Cu" "B.Cu")
		(net "GND")
	)
	(via
		(at 201.737214 -228.766624)
		(size 0.4572)
		(drill 0.2032)
		(layers "F.Cu" "B.Cu")
		(net "GND")
	)
	(via
		(at 59.626246 -276.366732)
		(size 0.4572)
		(drill 0.2032)
		(layers "F.Cu" "B.Cu")
		(net "GND")
	)
	(via
		(at 180.339746 -261.916672)
		(size 0.4572)
		(drill 0.2032)
		(layers "F.Cu" "B.Cu")
		(net "GND")
	)
	(via
		(at 12.584684 -323.434456)
		(size 0.4572)
		(drill 0.2032)
		(layers "F.Cu" "B.Cu")
		(net "GND")
	)
	(via
		(at 195.427346 -298.466764)
		(size 0.4572)
		(drill 0.2032)
		(layers "F.Cu" "B.Cu")
		(net "GND")
	)
	(via
		(at 20.889214 -250.866656)
		(size 0.4572)
		(drill 0.2032)
		(layers "F.Cu" "B.Cu")
		(net "GND")
	)
	(via
		(at 266.619482 -312.91657)
		(size 0.4572)
		(drill 0.2032)
		(layers "F.Cu" "B.Cu")
		(net "GND")
	)
	(via
		(at 85.905594 -282.405836)
		(size 0.4572)
		(drill 0.2032)
		(layers "F.Cu" "B.Cu")
		(net "GND")
	)
	(via
		(at 41.310814 -200.716642)
		(size 0.4572)
		(drill 0.2032)
		(layers "F.Cu" "B.Cu")
		(net "GND")
	)
	(via
		(at 142.51178 -341.928196)
		(size 0.508)
		(drill 0.254)
		(layers "F.Cu" "B.Cu")
		(net "GND")
	)
	(via
		(at 191.983614 -196.466714)
		(size 0.4572)
		(drill 0.2032)
		(layers "F.Cu" "B.Cu")
		(net "GND")
	)
	(via
		(at 359.580434 -217.878406)
		(size 0.4572)
		(drill 0.2032)
		(layers "F.Cu" "B.Cu")
		(net "GND")
	)
	(via
		(at 63.942214 -295.916604)
		(size 0.4572)
		(drill 0.2032)
		(layers "F.Cu" "B.Cu")
		(net "GND")
	)
	(via
		(at 462.71434 -387.58241)
		(size 0.508)
		(drill 0.254)
		(layers "F.Cu" "B.Cu")
		(net "GND")
	)
	(via
		(at 405.349964 -439.651394)
		(size 0.4572)
		(drill 0.2032)
		(layers "F.Cu" "B.Cu")
		(net "GND")
	)
	(via
		(at 195.427346 -250.016772)
		(size 0.4572)
		(drill 0.2032)
		(layers "F.Cu" "B.Cu")
		(net "GND")
	)
	(via
		(at 422.945814 -240.666778)
		(size 0.4572)
		(drill 0.2032)
		(layers "F.Cu" "B.Cu")
		(net "GND")
	)
	(via
		(at 365.063532 -326.948292)
		(size 0.508)
		(drill 0.254)
		(layers "F.Cu" "B.Cu")
		(net "GND")
	)
	(via
		(at 172.795946 -217.716608)
		(size 0.4572)
		(drill 0.2032)
		(layers "F.Cu" "B.Cu")
		(net "GND")
	)
	(via
		(at 363.355636 -244.812312)
		(size 0.4572)
		(drill 0.2032)
		(layers "F.Cu" "B.Cu")
		(net "GND")
	)
	(via
		(at 18.54708 -10.16508)
		(size 0.508)
		(drill 0.254)
		(layers "F.Cu" "B.Cu")
		(net "GND")
	)
	(via
		(at 315.250068 -425.547282)
		(size 0.4572)
		(drill 0.2032)
		(layers "F.Cu" "B.Cu")
		(net "GND")
	)
	(via
		(at 88.255094 -263.686544)
		(size 0.4572)
		(drill 0.2032)
		(layers "F.Cu" "B.Cu")
		(net "GND")
	)
	(via
		(at 23.060152 -409.402534)
		(size 0.508)
		(drill 0.254)
		(layers "F.Cu" "B.Cu")
		(net "GND")
	)
	(via
		(at 171.562014 -202.416664)
		(size 0.4572)
		(drill 0.2032)
		(layers "F.Cu" "B.Cu")
		(net "GND")
	)
	(via
		(at 214.615014 -202.416664)
		(size 0.4572)
		(drill 0.2032)
		(layers "F.Cu" "B.Cu")
		(net "GND")
	)
	(via
		(at 90.964512 -240.667286)
		(size 0.4572)
		(drill 0.2032)
		(layers "F.Cu" "B.Cu")
		(net "GND")
	)
	(via
		(at 438.033414 -212.616796)
		(size 0.4572)
		(drill 0.2032)
		(layers "F.Cu" "B.Cu")
		(net "GND")
	)
	(via
		(at 324.054978 -33.762188)
		(size 0.49022)
		(drill 0.254)
		(layers "F.Cu" "B.Cu")
		(net "GND")
	)
	(via
		(at 411.958282 -226.216718)
		(size 0.4572)
		(drill 0.2032)
		(layers "F.Cu" "B.Cu")
		(net "GND")
	)
	(via
		(at 378.697998 -406.370536)
		(size 0.4572)
		(drill 0.254)
		(layers "F.Cu" "B.Cu")
		(net "GND")
	)
	(via
		(at 377.076462 -264.50036)
		(size 0.4572)
		(drill 0.2032)
		(layers "F.Cu" "B.Cu")
		(net "GND")
	)
	(via
		(at 368.916204 -236.25175)
		(size 0.4572)
		(drill 0.2032)
		(layers "F.Cu" "B.Cu")
		(net "GND")
	)
	(via
		(at 49.128426 -409.396184)
		(size 0.4572)
		(drill 0.254)
		(layers "F.Cu" "B.Cu")
		(net "GND")
	)
	(via
		(at 413.192214 -287.213548)
		(size 0.4572)
		(drill 0.2032)
		(layers "F.Cu" "B.Cu")
		(net "GND")
	)
	(via
		(at 439.923682 -284.866588)
		(size 0.4572)
		(drill 0.2032)
		(layers "F.Cu" "B.Cu")
		(net "GND")
	)
	(via
		(at 383.545334 -241.481102)
		(size 0.4572)
		(drill 0.2032)
		(layers "F.Cu" "B.Cu")
		(net "GND")
	)
	(via
		(at 314.092082 -245.76659)
		(size 0.4572)
		(drill 0.2032)
		(layers "F.Cu" "B.Cu")
		(net "GND")
	)
	(via
		(at 363.449362 -273.453098)
		(size 0.4572)
		(drill 0.2032)
		(layers "F.Cu" "B.Cu")
		(net "GND")
	)
	(via
		(at 202.971146 -263.616694)
		(size 0.4572)
		(drill 0.2032)
		(layers "F.Cu" "B.Cu")
		(net "GND")
	)
	(via
		(at 342.735154 -49.859692)
		(size 0.4572)
		(drill 0.2032)
		(layers "F.Cu" "B.Cu")
		(net "GND")
	)
	(via
		(at 144.741646 -342.129872)
		(size 0.508)
		(drill 0.254)
		(layers "F.Cu" "B.Cu")
		(net "GND")
	)
	(via
		(at 304.122582 -312.91657)
		(size 0.4572)
		(drill 0.2032)
		(layers "F.Cu" "B.Cu")
		(net "GND")
	)
	(via
		(at 42.298366 -433.750212)
		(size 0.508)
		(drill 0.254)
		(layers "F.Cu" "B.Cu")
		(net "GND")
	)
	(via
		(at 347.473016 -266.941808)
		(size 0.4572)
		(drill 0.2032)
		(layers "F.Cu" "B.Cu")
		(net "GND")
	)
	(via
		(at 420.156894 -9.424924)
		(size 0.508)
		(drill 0.254)
		(layers "F.Cu" "B.Cu")
		(net "GND")
	)
	(via
		(at 136.545066 -231.714548)
		(size 0.4318)
		(drill 0.2032)
		(layers "F.Cu" "B.Cu")
		(net "GND")
	)
	(via
		(at 101.882194 -275.8948)
		(size 0.4572)
		(drill 0.2032)
		(layers "F.Cu" "B.Cu")
		(net "GND")
	)
	(via
		(at 336.08518 -214.622634)
		(size 0.4572)
		(drill 0.2032)
		(layers "F.Cu" "B.Cu")
		(net "GND")
	)
	(via
		(at 123.027694 -286.475424)
		(size 0.4572)
		(drill 0.2032)
		(layers "F.Cu" "B.Cu")
		(net "GND")
	)
	(via
		(at 149.349968 -432.451256)
		(size 0.4572)
		(drill 0.2032)
		(layers "F.Cu" "B.Cu")
		(net "GND")
	)
	(via
		(at 428.279814 -197.316598)
		(size 0.4572)
		(drill 0.2032)
		(layers "F.Cu" "B.Cu")
		(net "GND")
	)
	(via
		(at 327.98512 -14.798548)
		(size 0.508)
		(drill 0.254)
		(layers "F.Cu" "B.Cu")
		(net "GND")
	)
	(via
		(at 378.846334 -213.732618)
		(size 0.4572)
		(drill 0.2032)
		(layers "F.Cu" "B.Cu")
		(net "GND")
	)
	(via
		(at 175.005746 -251.716794)
		(size 0.4572)
		(drill 0.2032)
		(layers "F.Cu" "B.Cu")
		(net "GND")
	)
	(via
		(at 419.502082 -264.466578)
		(size 0.4572)
		(drill 0.2032)
		(layers "F.Cu" "B.Cu")
		(net "GND")
	)
	(via
		(at 420.7637 -174.519844)
		(size 0.508)
		(drill 0.254)
		(layers "F.Cu" "B.Cu")
		(net "GND")
	)
	(via
		(at 367.208816 -286.475424)
		(size 0.4572)
		(drill 0.2032)
		(layers "F.Cu" "B.Cu")
		(net "GND")
	)
	(via
		(at 35.976814 -232.166668)
		(size 0.4572)
		(drill 0.2032)
		(layers "F.Cu" "B.Cu")
		(net "GND")
	)
	(via
		(at 174.1424 -95.367348)
		(size 0.508)
		(drill 0.254)
		(layers "F.Cu" "B.Cu")
		(net "GND")
	)
	(via
		(at 129.496312 -243.922804)
		(size 0.4572)
		(drill 0.2032)
		(layers "F.Cu" "B.Cu")
		(net "GND")
	)
	(via
		(at 145.757646 -342.129872)
		(size 0.508)
		(drill 0.254)
		(layers "F.Cu" "B.Cu")
		(net "GND")
	)
	(via
		(at 277.607014 -227.066602)
		(size 0.4572)
		(drill 0.2032)
		(layers "F.Cu" "B.Cu")
		(net "GND")
	)
	(via
		(at 314.318396 -406.370536)
		(size 0.4572)
		(drill 0.254)
		(layers "F.Cu" "B.Cu")
		(net "GND")
	)
	(via
		(at 378.956062 -267.755878)
		(size 0.4572)
		(drill 0.2032)
		(layers "F.Cu" "B.Cu")
		(net "GND")
	)
	(via
		(at 434.589682 -226.216718)
		(size 0.4572)
		(drill 0.2032)
		(layers "F.Cu" "B.Cu")
		(net "GND")
	)
	(via
		(at 97.24644 -119.664988)
		(size 0.508)
		(drill 0.254)
		(layers "F.Cu" "B.Cu")
		(net "GND")
	)
	(via
		(at 415.402014 -292.516814)
		(size 0.4572)
		(drill 0.2032)
		(layers "F.Cu" "B.Cu")
		(net "GND")
	)
	(via
		(at 262.519414 -317.166752)
		(size 0.4572)
		(drill 0.2032)
		(layers "F.Cu" "B.Cu")
		(net "GND")
	)
	(via
		(at 24.332946 -313.766708)
		(size 0.4572)
		(drill 0.2032)
		(layers "F.Cu" "B.Cu")
		(net "GND")
	)
	(via
		(at 434.589682 -245.76659)
		(size 0.4572)
		(drill 0.2032)
		(layers "F.Cu" "B.Cu")
		(net "GND")
	)
	(via
		(at 292.694614 -208.366614)
		(size 0.4572)
		(drill 0.2032)
		(layers "F.Cu" "B.Cu")
		(net "GND")
	)
	(via
		(at 314.092082 -266.1666)
		(size 0.4572)
		(drill 0.2032)
		(layers "F.Cu" "B.Cu")
		(net "GND")
	)
	(via
		(at 309.992014 -292.516814)
		(size 0.4572)
		(drill 0.2032)
		(layers "F.Cu" "B.Cu")
		(net "GND")
	)
	(via
		(at 115.716304 -362.618528)
		(size 0.508)
		(drill 0.254)
		(layers "F.Cu" "B.Cu")
		(net "GND")
	)
	(via
		(at 349.369888 -400.858228)
		(size 0.4064)
		(drill 0.2032)
		(layers "F.Cu" "B.Cu")
		(net "GND")
	)
	(via
		(at 377.25477 -410.030168)
		(size 0.4064)
		(drill 0.2032)
		(layers "F.Cu" "B.Cu")
		(net "GND")
	)
	(via
		(at 190.093346 -242.3668)
		(size 0.4572)
		(drill 0.2032)
		(layers "F.Cu" "B.Cu")
		(net "GND")
	)
	(via
		(at 115.979448 -274.266914)
		(size 0.4572)
		(drill 0.2032)
		(layers "F.Cu" "B.Cu")
		(net "GND")
	)
	(via
		(at 202.971146 -300.166786)
		(size 0.4572)
		(drill 0.2032)
		(layers "F.Cu" "B.Cu")
		(net "GND")
	)
	(via
		(at 431.5841 -353.977702)
		(size 0.508)
		(drill 0.254)
		(layers "F.Cu" "B.Cu")
		(net "GND")
	)
	(via
		(at 199.527414 -266.1666)
		(size 0.4572)
		(drill 0.2032)
		(layers "F.Cu" "B.Cu")
		(net "GND")
	)
	(via
		(at 116.415058 -331.21092)
		(size 0.508)
		(drill 0.254)
		(layers "F.Cu" "B.Cu")
		(net "GND")
	)
	(via
		(at 384.594862 -285.661354)
		(size 0.4572)
		(drill 0.2032)
		(layers "F.Cu" "B.Cu")
		(net "GND")
	)
	(via
		(at 102.900988 -245.337584)
		(size 0.4572)
		(drill 0.2032)
		(layers "F.Cu" "B.Cu")
		(net "GND")
	)
	(via
		(at 11.135614 -295.916604)
		(size 0.4572)
		(drill 0.2032)
		(layers "F.Cu" "B.Cu")
		(net "GND")
	)
	(via
		(at 133.35 -10.733278)
		(size 0.508)
		(drill 0.254)
		(layers "F.Cu" "B.Cu")
		(net "GND")
	)
	(via
		(at 372.847616 -281.59202)
		(size 0.4572)
		(drill 0.2032)
		(layers "F.Cu" "B.Cu")
		(net "GND")
	)
	(via
		(at 73.106026 -175.538638)
		(size 0.508)
		(drill 0.254)
		(layers "F.Cu" "B.Cu")
		(net "GND")
	)
	(via
		(at 158.38932 -85.452966)
		(size 0.508)
		(drill 0.254)
		(layers "F.Cu" "B.Cu")
		(net "GND")
	)
	(via
		(at 7.035546 -306.116736)
		(size 0.4572)
		(drill 0.2032)
		(layers "F.Cu" "B.Cu")
		(net "GND")
	)
	(via
		(at 169.352214 -258.516628)
		(size 0.4572)
		(drill 0.2032)
		(layers "F.Cu" "B.Cu")
		(net "GND")
	)
	(via
		(at 390.950958 -410.664152)
		(size 0.4572)
		(drill 0.254)
		(layers "F.Cu" "B.Cu")
		(net "GND")
	)
	(via
		(at 43.582082 -16.978376)
		(size 0.508)
		(drill 0.254)
		(layers "F.Cu" "B.Cu")
		(net "GND")
	)
	(via
		(at 307.456078 -421.23741)
		(size 0.508)
		(drill 0.254)
		(layers "F.Cu" "B.Cu")
		(net "GND")
	)
	(via
		(at 455.011282 -282.316682)
		(size 0.4572)
		(drill 0.2032)
		(layers "F.Cu" "B.Cu")
		(net "GND")
	)
	(via
		(at 100.817934 -393.65174)
		(size 0.508)
		(drill 0.254)
		(layers "F.Cu" "B.Cu")
		(net "GND")
	)
	(via
		(at 59.57697 -410.664152)
		(size 0.4572)
		(drill 0.254)
		(layers "F.Cu" "B.Cu")
		(net "GND")
	)
	(via
		(at 339.484462 -279.150318)
		(size 0.4572)
		(drill 0.2032)
		(layers "F.Cu" "B.Cu")
		(net "GND")
	)
	(via
		(at 195.02628 -358.206548)
		(size 0.508)
		(drill 0.254)
		(layers "F.Cu" "B.Cu")
		(net "GND")
	)
	(via
		(at 264.729214 -301.866808)
		(size 0.4572)
		(drill 0.2032)
		(layers "F.Cu" "B.Cu")
		(net "GND")
	)
	(via
		(at 299.004482 -196.466714)
		(size 0.4572)
		(drill 0.2032)
		(layers "F.Cu" "B.Cu")
		(net "GND")
	)
	(via
		(at 214.615014 -306.96662)
		(size 0.4572)
		(drill 0.2032)
		(layers "F.Cu" "B.Cu")
		(net "GND")
	)
	(via
		(at 214.615014 -244.066568)
		(size 0.4572)
		(drill 0.2032)
		(layers "F.Cu" "B.Cu")
		(net "GND")
	)
	(via
		(at 67.202812 -39.421562)
		(size 0.508)
		(drill 0.254)
		(layers "F.Cu" "B.Cu")
		(net "GND")
	)
	(via
		(at 35.976814 -200.716642)
		(size 0.4572)
		(drill 0.2032)
		(layers "F.Cu" "B.Cu")
		(net "GND")
	)
	(via
		(at 62.051946 -248.31675)
		(size 0.4572)
		(drill 0.2032)
		(layers "F.Cu" "B.Cu")
		(net "GND")
	)
	(via
		(at 354.411534 -223.575626)
		(size 0.4572)
		(drill 0.2032)
		(layers "F.Cu" "B.Cu")
		(net "GND")
	)
	(via
		(at 254.975614 -287.416748)
		(size 0.4572)
		(drill 0.2032)
		(layers "F.Cu" "B.Cu")
		(net "GND")
	)
	(via
		(at 197.637146 -208.366614)
		(size 0.4572)
		(drill 0.2032)
		(layers "F.Cu" "B.Cu")
		(net "GND")
	)
	(via
		(at 246.940832 -439.905394)
		(size 0.508)
		(drill 0.254)
		(layers "F.Cu" "B.Cu")
		(net "GND")
	)
	(via
		(at 410.361638 -364.151926)
		(size 0.508)
		(drill 0.254)
		(layers "F.Cu" "B.Cu")
		(net "GND")
	)
	(via
		(at 334.315308 -275.08073)
		(size 0.4318)
		(drill 0.2032)
		(layers "F.Cu" "B.Cu")
		(net "GND")
	)
	(via
		(at 430.97704 -121.464578)
		(size 0.508)
		(drill 0.254)
		(layers "F.Cu" "B.Cu")
		(net "GND")
	)
	(via
		(at 176.896014 -249.166634)
		(size 0.4572)
		(drill 0.2032)
		(layers "F.Cu" "B.Cu")
		(net "GND")
	)
	(via
		(at 155.349956 -438.651396)
		(size 0.4572)
		(drill 0.2032)
		(layers "F.Cu" "B.Cu")
		(net "GND")
	)
	(via
		(at 449.677282 -261.066788)
		(size 0.4572)
		(drill 0.2032)
		(layers "F.Cu" "B.Cu")
		(net "GND")
	)
	(via
		(at 57.956958 -407.00452)
		(size 0.4064)
		(drill 0.2032)
		(layers "F.Cu" "B.Cu")
		(net "GND")
	)
	(via
		(at 137.159238 -342.556084)
		(size 0.49022)
		(drill 0.254)
		(layers "F.Cu" "B.Cu")
		(net "GND")
	)
	(via
		(at 9.245346 -315.46673)
		(size 0.4572)
		(drill 0.2032)
		(layers "F.Cu" "B.Cu")
		(net "GND")
	)
	(via
		(at 339.644736 -333.833724)
		(size 0.508)
		(drill 0.254)
		(layers "F.Cu" "B.Cu")
		(net "GND")
	)
	(via
		(at 336.121248 -82.72018)
		(size 0.508)
		(drill 0.254)
		(layers "F.Cu" "B.Cu")
		(net "GND")
	)
	(via
		(at 130.66395 -125.758448)
		(size 0.508)
		(drill 0.254)
		(layers "F.Cu" "B.Cu")
		(net "GND")
	)
	(via
		(at 360.566716 -331.776832)
		(size 0.49022)
		(drill 0.254)
		(layers "F.Cu" "B.Cu")
		(net "GND")
	)
	(via
		(at 164.018214 -249.166634)
		(size 0.4572)
		(drill 0.2032)
		(layers "F.Cu" "B.Cu")
		(net "GND")
	)
	(via
		(at 411.958282 -305.266598)
		(size 0.4572)
		(drill 0.2032)
		(layers "F.Cu" "B.Cu")
		(net "GND")
	)
	(via
		(at 166.233856 -11.463782)
		(size 0.508)
		(drill 0.254)
		(layers "F.Cu" "B.Cu")
		(net "GND")
	)
	(via
		(at 323.42074 -400.200368)
		(size 0.4572)
		(drill 0.254)
		(layers "F.Cu" "B.Cu")
		(net "GND")
	)
	(via
		(at 106.06405 -254.01524)
		(size 0.4572)
		(drill 0.2032)
		(layers "F.Cu" "B.Cu")
		(net "GND")
	)
	(via
		(at 63.942214 -233.86669)
		(size 0.4572)
		(drill 0.2032)
		(layers "F.Cu" "B.Cu")
		(net "GND")
	)
	(via
		(at 108.43387 -259.578602)
		(size 0.4572)
		(drill 0.2032)
		(layers "F.Cu" "B.Cu")
		(net "GND")
	)
	(via
		(at 334.67548 -234.970066)
		(size 0.4318)
		(drill 0.2032)
		(layers "F.Cu" "B.Cu")
		(net "GND")
	)
	(via
		(at 272.273014 -283.166566)
		(size 0.4572)
		(drill 0.2032)
		(layers "F.Cu" "B.Cu")
		(net "GND")
	)
	(via
		(at 353.001834 -216.25052)
		(size 0.4572)
		(drill 0.2032)
		(layers "F.Cu" "B.Cu")
		(net "GND")
	)
	(via
		(at 415.903664 -362.649262)
		(size 0.49022)
		(drill 0.254)
		(layers "F.Cu" "B.Cu")
		(net "GND")
	)
	(via
		(at 149.498558 -72.608948)
		(size 0.508)
		(drill 0.254)
		(layers "F.Cu" "B.Cu")
		(net "GND")
	)
	(via
		(at 201.737214 -235.566712)
		(size 0.4572)
		(drill 0.2032)
		(layers "F.Cu" "B.Cu")
		(net "GND")
	)
	(via
		(at 119.158766 -222.761556)
		(size 0.4572)
		(drill 0.2032)
		(layers "F.Cu" "B.Cu")
		(net "GND")
	)
	(via
		(at 182.549546 -231.316784)
		(size 0.4572)
		(drill 0.2032)
		(layers "F.Cu" "B.Cu")
		(net "GND")
	)
	(via
		(at 29.666946 -315.46673)
		(size 0.4572)
		(drill 0.2032)
		(layers "F.Cu" "B.Cu")
		(net "GND")
	)
	(via
		(at 432.379882 -247.466612)
		(size 0.4572)
		(drill 0.2032)
		(layers "F.Cu" "B.Cu")
		(net "GND")
	)
	(via
		(at 24.332946 -223.666558)
		(size 0.4572)
		(drill 0.2032)
		(layers "F.Cu" "B.Cu")
		(net "GND")
	)
	(via
		(at 413.192214 -296.766742)
		(size 0.4572)
		(drill 0.2032)
		(layers "F.Cu" "B.Cu")
		(net "GND")
	)
	(via
		(at 449.677282 -295.916604)
		(size 0.4572)
		(drill 0.2032)
		(layers "F.Cu" "B.Cu")
		(net "GND")
	)
	(via
		(at 260.02996 -151.422608)
		(size 0.508)
		(drill 0.254)
		(layers "F.Cu" "B.Cu")
		(net "GND")
	)
	(via
		(at 94.363794 -287.28924)
		(size 0.4572)
		(drill 0.2032)
		(layers "F.Cu" "B.Cu")
		(net "GND")
	)
	(via
		(at 151.96693 -43.652948)
		(size 0.508)
		(drill 0.254)
		(layers "F.Cu" "B.Cu")
		(net "GND")
	)
	(via
		(at 417.15436 -157.110684)
		(size 0.508)
		(drill 0.254)
		(layers "F.Cu" "B.Cu")
		(net "GND")
	)
	(via
		(at 190.093346 -244.916706)
		(size 0.4572)
		(drill 0.2032)
		(layers "F.Cu" "B.Cu")
		(net "GND")
	)
	(via
		(at 418.520118 -410.664152)
		(size 0.4572)
		(drill 0.254)
		(layers "F.Cu" "B.Cu")
		(net "GND")
	)
	(via
		(at 292.694614 -307.816758)
		(size 0.4572)
		(drill 0.2032)
		(layers "F.Cu" "B.Cu")
		(net "GND")
	)
	(via
		(at 194.193414 -211.766658)
		(size 0.4572)
		(drill 0.2032)
		(layers "F.Cu" "B.Cu")
		(net "GND")
	)
	(via
		(at 63.942214 -244.066568)
		(size 0.4572)
		(drill 0.2032)
		(layers "F.Cu" "B.Cu")
		(net "GND")
	)
	(via
		(at 96.75622 -388.976108)
		(size 0.4572)
		(drill 0.254)
		(layers "F.Cu" "B.Cu")
		(net "GND")
	)
	(via
		(at 324.863968 -403.883876)
		(size 0.4064)
		(drill 0.2032)
		(layers "F.Cu" "B.Cu")
		(net "GND")
	)
	(via
		(at 157.708346 -233.016806)
		(size 0.4572)
		(drill 0.2032)
		(layers "F.Cu" "B.Cu")
		(net "GND")
	)
	(via
		(at 404.462742 -407.638504)
		(size 0.4572)
		(drill 0.254)
		(layers "F.Cu" "B.Cu")
		(net "GND")
	)
	(via
		(at 302.448214 -199.01662)
		(size 0.4572)
		(drill 0.2032)
		(layers "F.Cu" "B.Cu")
		(net "GND")
	)
	(via
		(at 29.666946 -195.616576)
		(size 0.4572)
		(drill 0.2032)
		(layers "F.Cu" "B.Cu")
		(net "GND")
	)
	(via
		(at 27.823668 -5.596636)
		(size 0.508)
		(drill 0.254)
		(layers "F.Cu" "B.Cu")
		(net "GND")
	)
	(via
		(at 277.386288 -440.497976)
		(size 0.508)
		(drill 0.254)
		(layers "F.Cu" "B.Cu")
		(net "GND")
	)
	(via
		(at 209.281014 -282.316682)
		(size 0.4572)
		(drill 0.2032)
		(layers "F.Cu" "B.Cu")
		(net "GND")
	)
	(via
		(at 335.42478 -335.976214)
		(size 0.49022)
		(drill 0.254)
		(layers "F.Cu" "B.Cu")
		(net "GND")
	)
	(via
		(at 176.896014 -277.216616)
		(size 0.4572)
		(drill 0.2032)
		(layers "F.Cu" "B.Cu")
		(net "GND")
	)
	(via
		(at 217.82024 -106.111548)
		(size 0.508)
		(drill 0.254)
		(layers "F.Cu" "B.Cu")
		(net "GND")
	)
	(via
		(at 296.794682 -230.466646)
		(size 0.4572)
		(drill 0.2032)
		(layers "F.Cu" "B.Cu")
		(net "GND")
	)
	(via
		(at 205.180946 -236.416596)
		(size 0.4572)
		(drill 0.2032)
		(layers "F.Cu" "B.Cu")
		(net "GND")
	)
	(via
		(at 126.786894 -279.964134)
		(size 0.4572)
		(drill 0.2032)
		(layers "F.Cu" "B.Cu")
		(net "GND")
	)
	(via
		(at 125.267466 -234.970066)
		(size 0.4572)
		(drill 0.2032)
		(layers "F.Cu" "B.Cu")
		(net "GND")
	)
	(via
		(at 56.398414 -250.866656)
		(size 0.4572)
		(drill 0.2032)
		(layers "F.Cu" "B.Cu")
		(net "GND")
	)
	(via
		(at 311.882282 -194.766692)
		(size 0.4572)
		(drill 0.2032)
		(layers "F.Cu" "B.Cu")
		(net "GND")
	)
	(via
		(at 428.030386 -361.734862)
		(size 0.49022)
		(drill 0.254)
		(layers "F.Cu" "B.Cu")
		(net "GND")
	)
	(via
		(at 6.617716 -49.567592)
		(size 0.508)
		(drill 0.254)
		(layers "F.Cu" "B.Cu")
		(net "GND")
	)
	(via
		(at 194.193414 -224.516696)
		(size 0.4572)
		(drill 0.2032)
		(layers "F.Cu" "B.Cu")
		(net "GND")
	)
	(via
		(at 171.355512 -112.57534)
		(size 0.4572)
		(drill 0.254)
		(layers "F.Cu" "B.Cu")
		(net "GND")
	)
	(via
		(at 84.250022 -426.69968)
		(size 0.4572)
		(drill 0.2032)
		(layers "F.Cu" "B.Cu")
		(net "GND")
	)
	(via
		(at 126.083822 -401.492212)
		(size 0.4572)
		(drill 0.254)
		(layers "F.Cu" "B.Cu")
		(net "GND")
	)
	(via
		(at 307.782214 -197.316598)
		(size 0.4572)
		(drill 0.2032)
		(layers "F.Cu" "B.Cu")
		(net "GND")
	)
	(via
		(at 432.379882 -226.216718)
		(size 0.4572)
		(drill 0.2032)
		(layers "F.Cu" "B.Cu")
		(net "GND")
	)
	(via
		(at 343.585292 -332.56601)
		(size 0.49022)
		(drill 0.254)
		(layers "F.Cu" "B.Cu")
		(net "GND")
	)
	(via
		(at 431.270156 -108.49737)
		(size 0.508)
		(drill 0.254)
		(layers "F.Cu" "B.Cu")
		(net "GND")
	)
	(via
		(at 294.904414 -220.266768)
		(size 0.4572)
		(drill 0.2032)
		(layers "F.Cu" "B.Cu")
		(net "GND")
	)
	(via
		(at 205.180946 -287.416748)
		(size 0.4572)
		(drill 0.2032)
		(layers "F.Cu" "B.Cu")
		(net "GND")
	)
	(via
		(at 90.306398 -400.858228)
		(size 0.4064)
		(drill 0.2032)
		(layers "F.Cu" "B.Cu")
		(net "GND")
	)
	(via
		(at 68.863718 -400.858228)
		(size 0.4064)
		(drill 0.2032)
		(layers "F.Cu" "B.Cu")
		(net "GND")
	)
	(via
		(at 359.11028 -231.714548)
		(size 0.4572)
		(drill 0.2032)
		(layers "F.Cu" "B.Cu")
		(net "GND")
	)
	(via
		(at 31.876746 -223.666558)
		(size 0.4572)
		(drill 0.2032)
		(layers "F.Cu" "B.Cu")
		(net "GND")
	)
	(via
		(at 344.25001 -427.851316)
		(size 0.4572)
		(drill 0.2032)
		(layers "F.Cu" "B.Cu")
		(net "GND")
	)
	(via
		(at 281.707082 -204.116686)
		(size 0.4572)
		(drill 0.2032)
		(layers "F.Cu" "B.Cu")
		(net "GND")
	)
	(via
		(at 184.61482 -420.46652)
		(size 0.508)
		(drill 0.254)
		(layers "F.Cu" "B.Cu")
		(net "GND")
	)
	(via
		(at 239.99952 -55.005986)
		(size 0.508)
		(drill 0.254)
		(layers "F.Cu" "B.Cu")
		(net "GND")
	)
	(via
		(at 140.706602 -339.831172)
		(size 0.508)
		(drill 0.254)
		(layers "F.Cu" "B.Cu")
		(net "GND")
	)
	(via
		(at 384.015234 -234.15625)
		(size 0.4572)
		(drill 0.2032)
		(layers "F.Cu" "B.Cu")
		(net "GND")
	)
	(via
		(at 373.787416 -263.686544)
		(size 0.4572)
		(drill 0.2032)
		(layers "F.Cu" "B.Cu")
		(net "GND")
	)
	(via
		(at 132.895848 -274.266914)
		(size 0.4572)
		(drill 0.2032)
		(layers "F.Cu" "B.Cu")
		(net "GND")
	)
	(via
		(at 127.726694 -257.175254)
		(size 0.4572)
		(drill 0.2032)
		(layers "F.Cu" "B.Cu")
		(net "GND")
	)
	(via
		(at 207.071214 -245.76659)
		(size 0.4572)
		(drill 0.2032)
		(layers "F.Cu" "B.Cu")
		(net "GND")
	)
	(via
		(at 304.197258 -33.746186)
		(size 0.508)
		(drill 0.254)
		(layers "F.Cu" "B.Cu")
		(net "GND")
	)
	(via
		(at 63.942214 -316.316614)
		(size 0.4572)
		(drill 0.2032)
		(layers "F.Cu" "B.Cu")
		(net "GND")
	)
	(via
		(at 133.835394 -282.405836)
		(size 0.4572)
		(drill 0.2032)
		(layers "F.Cu" "B.Cu")
		(net "GND")
	)
	(via
		(at 429.764952 -385.521962)
		(size 0.508)
		(drill 0.254)
		(layers "F.Cu" "B.Cu")
		(net "GND")
	)
	(via
		(at 302.448214 -298.466764)
		(size 0.4572)
		(drill 0.2032)
		(layers "F.Cu" "B.Cu")
		(net "GND")
	)
	(via
		(at 396.349982 -426.54728)
		(size 0.4572)
		(drill 0.2032)
		(layers "F.Cu" "B.Cu")
		(net "GND")
	)
	(via
		(at 411.47492 -150.03399)
		(size 0.508)
		(drill 0.254)
		(layers "F.Cu" "B.Cu")
		(net "GND")
	)
	(via
		(at 344.07348 -249.620024)
		(size 0.4572)
		(drill 0.2032)
		(layers "F.Cu" "B.Cu")
		(net "GND")
	)
	(via
		(at 299.004482 -282.316682)
		(size 0.4572)
		(drill 0.2032)
		(layers "F.Cu" "B.Cu")
		(net "GND")
	)
	(via
		(at 66.152014 -275.516594)
		(size 0.4572)
		(drill 0.2032)
		(layers "F.Cu" "B.Cu")
		(net "GND")
	)
	(via
		(at 229.61092 -53.43017)
		(size 0.508)
		(drill 0.254)
		(layers "F.Cu" "B.Cu")
		(net "GND")
	)
	(via
		(at 176.896014 -202.416664)
		(size 0.4572)
		(drill 0.2032)
		(layers "F.Cu" "B.Cu")
		(net "GND")
	)
	(via
		(at 447.467482 -294.216582)
		(size 0.4572)
		(drill 0.2032)
		(layers "F.Cu" "B.Cu")
		(net "GND")
	)
	(via
		(at 59.626246 -220.342968)
		(size 0.4572)
		(drill 0.2032)
		(layers "F.Cu" "B.Cu")
		(net "GND")
	)
	(via
		(at 132.350002 -427.699678)
		(size 0.4572)
		(drill 0.2032)
		(layers "F.Cu" "B.Cu")
		(net "GND")
	)
	(via
		(at 462.316576 -101.105208)
		(size 0.508)
		(drill 0.254)
		(layers "F.Cu" "B.Cu")
		(net "GND")
	)
	(via
		(at 390.863582 -403.249892)
		(size 0.4572)
		(drill 0.254)
		(layers "F.Cu" "B.Cu")
		(net "GND")
	)
	(via
		(at 33.767014 -291.666676)
		(size 0.4572)
		(drill 0.2032)
		(layers "F.Cu" "B.Cu")
		(net "GND")
	)
	(via
		(at 108.578396 -360.753406)
		(size 0.508)
		(drill 0.254)
		(layers "F.Cu" "B.Cu")
		(net "GND")
	)
	(via
		(at 467.535514 -139.56538)
		(size 0.508)
		(drill 0.254)
		(layers "F.Cu" "B.Cu")
		(net "GND")
	)
	(via
		(at 434.589682 -316.316614)
		(size 0.4572)
		(drill 0.2032)
		(layers "F.Cu" "B.Cu")
		(net "GND")
	)
	(via
		(at 266.619482 -280.61666)
		(size 0.4572)
		(drill 0.2032)
		(layers "F.Cu" "B.Cu")
		(net "GND")
	)
	(via
		(at 197.637146 -258.516628)
		(size 0.4572)
		(drill 0.2032)
		(layers "F.Cu" "B.Cu")
		(net "GND")
	)
	(via
		(at 409.568396 -216.90457)
		(size 0.4572)
		(drill 0.2032)
		(layers "F.Cu" "B.Cu")
		(net "GND")
	)
	(via
		(at 399.990056 -4.317746)
		(size 0.508)
		(drill 0.254)
		(layers "F.Cu" "B.Cu")
		(net "GND")
	)
	(via
		(at 302.448214 -301.866808)
		(size 0.4572)
		(drill 0.2032)
		(layers "F.Cu" "B.Cu")
		(net "GND")
	)
	(via
		(at 190.093346 -306.116736)
		(size 0.4572)
		(drill 0.2032)
		(layers "F.Cu" "B.Cu")
		(net "GND")
	)
	(via
		(at 66.04 -7.203948)
		(size 0.508)
		(drill 0.254)
		(layers "F.Cu" "B.Cu")
		(net "GND")
	)
	(via
		(at 14.579346 -233.016806)
		(size 0.4572)
		(drill 0.2032)
		(layers "F.Cu" "B.Cu")
		(net "GND")
	)
	(via
		(at 39.420546 -290.816792)
		(size 0.4572)
		(drill 0.2032)
		(layers "F.Cu" "B.Cu")
		(net "GND")
	)
	(via
		(at 261.42188 -132.088128)
		(size 0.508)
		(drill 0.254)
		(layers "F.Cu" "B.Cu")
		(net "GND")
	)
	(via
		(at 195.427346 -223.666558)
		(size 0.4572)
		(drill 0.2032)
		(layers "F.Cu" "B.Cu")
		(net "GND")
	)
	(via
		(at 337.495134 -220.319854)
		(size 0.4572)
		(drill 0.2032)
		(layers "F.Cu" "B.Cu")
		(net "GND")
	)
	(via
		(at 56.398414 -245.76659)
		(size 0.4572)
		(drill 0.2032)
		(layers "F.Cu" "B.Cu")
		(net "GND")
	)
	(via
		(at 262.519414 -313.766708)
		(size 0.4572)
		(drill 0.2032)
		(layers "F.Cu" "B.Cu")
		(net "GND")
	)
	(via
		(at 236.143292 -127.91313)
		(size 0.508)
		(drill 0.254)
		(layers "F.Cu" "B.Cu")
		(net "GND")
	)
	(via
		(at 215.392 -95.153988)
		(size 0.508)
		(drill 0.254)
		(layers "F.Cu" "B.Cu")
		(net "GND")
	)
	(via
		(at 420.736014 -223.666558)
		(size 0.4572)
		(drill 0.2032)
		(layers "F.Cu" "B.Cu")
		(net "GND")
	)
	(via
		(at 129.393442 -337.692238)
		(size 0.49022)
		(drill 0.254)
		(layers "F.Cu" "B.Cu")
		(net "GND")
	)
	(via
		(at 419.502082 -198.166736)
		(size 0.4572)
		(drill 0.2032)
		(layers "F.Cu" "B.Cu")
		(net "GND")
	)
	(via
		(at 285.150814 -197.316598)
		(size 0.4572)
		(drill 0.2032)
		(layers "F.Cu" "B.Cu")
		(net "GND")
	)
	(via
		(at 292.694614 -289.11677)
		(size 0.4572)
		(drill 0.2032)
		(layers "F.Cu" "B.Cu")
		(net "GND")
	)
	(via
		(at 348.412562 -286.475424)
		(size 0.4572)
		(drill 0.2032)
		(layers "F.Cu" "B.Cu")
		(net "GND")
	)
	(via
		(at 56.182514 -238.116618)
		(size 0.4572)
		(drill 0.2032)
		(layers "F.Cu" "B.Cu")
		(net "GND")
	)
	(via
		(at 13.345414 -215.166702)
		(size 0.4572)
		(drill 0.2032)
		(layers "F.Cu" "B.Cu")
		(net "GND")
	)
	(via
		(at 346.250006 -434.899562)
		(size 0.4572)
		(drill 0.2032)
		(layers "F.Cu" "B.Cu")
		(net "GND")
	)
	(via
		(at 369.558062 -284.033722)
		(size 0.4572)
		(drill 0.2032)
		(layers "F.Cu" "B.Cu")
		(net "GND")
	)
	(via
		(at 323.508116 -406.34666)
		(size 0.4572)
		(drill 0.254)
		(layers "F.Cu" "B.Cu")
		(net "GND")
	)
	(via
		(at 299.004482 -278.916638)
		(size 0.4572)
		(drill 0.2032)
		(layers "F.Cu" "B.Cu")
		(net "GND")
	)
	(via
		(at 37.373814 -177.497994)
		(size 0.508)
		(drill 0.254)
		(layers "F.Cu" "B.Cu")
		(net "GND")
	)
	(via
		(at 28.433014 -216.866724)
		(size 0.4572)
		(drill 0.2032)
		(layers "F.Cu" "B.Cu")
		(net "GND")
	)
	(via
		(at 28.67533 -441.225432)
		(size 0.508)
		(drill 0.254)
		(layers "F.Cu" "B.Cu")
		(net "GND")
	)
	(via
		(at 182.549546 -214.316564)
		(size 0.4572)
		(drill 0.2032)
		(layers "F.Cu" "B.Cu")
		(net "GND")
	)
	(via
		(at 415.648648 -170.802554)
		(size 0.49022)
		(drill 0.254)
		(layers "F.Cu" "B.Cu")
		(net "GND")
	)
	(via
		(at 131.569206 -330.227432)
		(size 0.508)
		(drill 0.254)
		(layers "F.Cu" "B.Cu")
		(net "GND")
	)
	(via
		(at 261.285482 -211.766658)
		(size 0.4572)
		(drill 0.2032)
		(layers "F.Cu" "B.Cu")
		(net "GND")
	)
	(via
		(at 289.250882 -272.966688)
		(size 0.4572)
		(drill 0.2032)
		(layers "F.Cu" "B.Cu")
		(net "GND")
	)
	(via
		(at 49.402238 -403.883876)
		(size 0.4064)
		(drill 0.2032)
		(layers "F.Cu" "B.Cu")
		(net "GND")
	)
	(via
		(at 52.298346 -199.01662)
		(size 0.4572)
		(drill 0.2032)
		(layers "F.Cu" "B.Cu")
		(net "GND")
	)
	(via
		(at 319.001648 -407.00452)
		(size 0.4064)
		(drill 0.2032)
		(layers "F.Cu" "B.Cu")
		(net "GND")
	)
	(via
		(at 416.556952 -10.16508)
		(size 0.508)
		(drill 0.254)
		(layers "F.Cu" "B.Cu")
		(net "GND")
	)
	(via
		(at 20.889214 -278.916638)
		(size 0.4572)
		(drill 0.2032)
		(layers "F.Cu" "B.Cu")
		(net "GND")
	)
	(via
		(at 190.093346 -300.166786)
		(size 0.4572)
		(drill 0.2032)
		(layers "F.Cu" "B.Cu")
		(net "GND")
	)
	(via
		(at 24.332946 -225.36658)
		(size 0.4572)
		(drill 0.2032)
		(layers "F.Cu" "B.Cu")
		(net "GND")
	)
	(via
		(at 24.332946 -214.316564)
		(size 0.4572)
		(drill 0.2032)
		(layers "F.Cu" "B.Cu")
		(net "GND")
	)
	(via
		(at 37.760402 -350.166178)
		(size 0.508)
		(drill 0.254)
		(layers "F.Cu" "B.Cu")
		(net "GND")
	)
	(via
		(at 179.105814 -261.066788)
		(size 0.4572)
		(drill 0.2032)
		(layers "F.Cu" "B.Cu")
		(net "GND")
	)
	(via
		(at 309.992014 -261.916672)
		(size 0.4572)
		(drill 0.2032)
		(layers "F.Cu" "B.Cu")
		(net "GND")
	)
	(via
		(at 285.150814 -260.21665)
		(size 0.4572)
		(drill 0.2032)
		(layers "F.Cu" "B.Cu")
		(net "GND")
	)
	(via
		(at 376.966734 -223.575626)
		(size 0.4572)
		(drill 0.2032)
		(layers "F.Cu" "B.Cu")
		(net "GND")
	)
	(via
		(at 135.591804 -361.45851)
		(size 0.6604)
		(drill 0.3302)
		(layers "F.Cu" "B.Cu")
		(net "GND")
	)
	(via
		(at 455.011282 -250.866656)
		(size 0.4572)
		(drill 0.2032)
		(layers "F.Cu" "B.Cu")
		(net "GND")
	)
	(via
		(at 348.014036 -409.396184)
		(size 0.4572)
		(drill 0.254)
		(layers "F.Cu" "B.Cu")
		(net "GND")
	)
	(via
		(at 444.771272 -66.579242)
		(size 0.508)
		(drill 0.254)
		(layers "F.Cu" "B.Cu")
		(net "GND")
	)
	(via
		(at 98.07448 -55.961788)
		(size 0.508)
		(drill 0.254)
		(layers "F.Cu" "B.Cu")
		(net "GND")
	)
	(via
		(at 259.588508 -68.616068)
		(size 0.508)
		(drill 0.254)
		(layers "F.Cu" "B.Cu")
		(net "GND")
	)
	(via
		(at 91.074494 -262.058658)
		(size 0.4572)
		(drill 0.2032)
		(layers "F.Cu" "B.Cu")
		(net "GND")
	)
	(via
		(at 161.605214 -275.516594)
		(size 0.4572)
		(drill 0.2032)
		(layers "F.Cu" "B.Cu")
		(net "GND")
	)
	(via
		(at 419.502082 -267.866622)
		(size 0.4572)
		(drill 0.2032)
		(layers "F.Cu" "B.Cu")
		(net "GND")
	)
	(via
		(at 372.84533 -403.883876)
		(size 0.4064)
		(drill 0.2032)
		(layers "F.Cu" "B.Cu")
		(net "GND")
	)
	(via
		(at 164.018214 -266.1666)
		(size 0.4572)
		(drill 0.2032)
		(layers "F.Cu" "B.Cu")
		(net "GND")
	)
	(via
		(at 124.437394 -275.8948)
		(size 0.4572)
		(drill 0.2032)
		(layers "F.Cu" "B.Cu")
		(net "GND")
	)
	(via
		(at 58.608214 -277.216616)
		(size 0.4572)
		(drill 0.2032)
		(layers "F.Cu" "B.Cu")
		(net "GND")
	)
	(via
		(at 109.77753 -330.382626)
		(size 0.508)
		(drill 0.254)
		(layers "F.Cu" "B.Cu")
		(net "GND")
	)
	(via
		(at 66.152014 -262.76681)
		(size 0.4572)
		(drill 0.2032)
		(layers "F.Cu" "B.Cu")
		(net "GND")
	)
	(via
		(at 169.141648 -312.91657)
		(size 0.4572)
		(drill 0.2032)
		(layers "F.Cu" "B.Cu")
		(net "GND")
	)
	(via
		(at 165.252146 -296.766742)
		(size 0.4572)
		(drill 0.2032)
		(layers "F.Cu" "B.Cu")
		(net "GND")
	)
	(via
		(at 201.737214 -267.866622)
		(size 0.4572)
		(drill 0.2032)
		(layers "F.Cu" "B.Cu")
		(net "GND")
	)
	(via
		(at 302.85436 -429.621188)
		(size 0.508)
		(drill 0.254)
		(layers "F.Cu" "B.Cu")
		(net "GND")
	)
	(via
		(at 85.905594 -269.38351)
		(size 0.4318)
		(drill 0.2032)
		(layers "F.Cu" "B.Cu")
		(net "GND")
	)
	(via
		(at 207.071214 -238.116618)
		(size 0.4572)
		(drill 0.2032)
		(layers "F.Cu" "B.Cu")
		(net "GND")
	)
	(via
		(at 353.066604 -331.776832)
		(size 0.49022)
		(drill 0.254)
		(layers "F.Cu" "B.Cu")
		(net "GND")
	)
	(via
		(at 164.018214 -308.666642)
		(size 0.4572)
		(drill 0.2032)
		(layers "F.Cu" "B.Cu")
		(net "GND")
	)
	(via
		(at 341.526368 -407.00452)
		(size 0.4064)
		(drill 0.2032)
		(layers "F.Cu" "B.Cu")
		(net "GND")
	)
	(via
		(at 182.34152 -351.614994)
		(size 0.49022)
		(drill 0.254)
		(layers "F.Cu" "B.Cu")
		(net "GND")
	)
	(via
		(at 455.011282 -278.916638)
		(size 0.4572)
		(drill 0.2032)
		(layers "F.Cu" "B.Cu")
		(net "GND")
	)
	(via
		(at 291.460682 -278.916638)
		(size 0.4572)
		(drill 0.2032)
		(layers "F.Cu" "B.Cu")
		(net "GND")
	)
	(via
		(at 165.252146 -238.966756)
		(size 0.4572)
		(drill 0.2032)
		(layers "F.Cu" "B.Cu")
		(net "GND")
	)
	(via
		(at 89.554812 -225.203258)
		(size 0.4572)
		(drill 0.2032)
		(layers "F.Cu" "B.Cu")
		(net "GND")
	)
	(via
		(at 259.075682 -232.166668)
		(size 0.4572)
		(drill 0.2032)
		(layers "F.Cu" "B.Cu")
		(net "GND")
	)
	(via
		(at 344.653362 -286.475424)
		(size 0.4572)
		(drill 0.2032)
		(layers "F.Cu" "B.Cu")
		(net "GND")
	)
	(via
		(at 350.292162 -289.807142)
		(size 0.4572)
		(drill 0.2032)
		(layers "F.Cu" "B.Cu")
		(net "GND")
	)
	(via
		(at 387.929628 -340.981792)
		(size 0.49022)
		(drill 0.254)
		(layers "F.Cu" "B.Cu")
		(net "GND")
	)
	(via
		(at 462.555082 -221.116652)
		(size 0.4572)
		(drill 0.2032)
		(layers "F.Cu" "B.Cu")
		(net "GND")
	)
	(via
		(at 162.828478 -418.759386)
		(size 0.508)
		(drill 0.254)
		(layers "F.Cu" "B.Cu")
		(net "GND")
	)
	(via
		(at 20.889214 -215.166702)
		(size 0.4572)
		(drill 0.2032)
		(layers "F.Cu" "B.Cu")
		(net "GND")
	)
	(via
		(at 209.281014 -272.966688)
		(size 0.4572)
		(drill 0.2032)
		(layers "F.Cu" "B.Cu")
		(net "GND")
	)
	(via
		(at 9.245346 -251.716794)
		(size 0.4572)
		(drill 0.2032)
		(layers "F.Cu" "B.Cu")
		(net "GND")
	)
	(via
		(at 182.549546 -307.816758)
		(size 0.4572)
		(drill 0.2032)
		(layers "F.Cu" "B.Cu")
		(net "GND")
	)
	(via
		(at 71.250048 -437.49976)
		(size 0.4572)
		(drill 0.2032)
		(layers "F.Cu" "B.Cu")
		(net "GND")
	)
	(via
		(at 261.389876 -98.519488)
		(size 0.508)
		(drill 0.254)
		(layers "F.Cu" "B.Cu")
		(net "GND")
	)
	(via
		(at 364.588298 -297.197526)
		(size 0.508)
		(drill 0.254)
		(layers "F.Cu" "B.Cu")
		(net "GND")
	)
	(via
		(at 172.795946 -278.066754)
		(size 0.4572)
		(drill 0.2032)
		(layers "F.Cu" "B.Cu")
		(net "GND")
	)
	(via
		(at 55.703724 -177.327052)
		(size 0.508)
		(drill 0.254)
		(layers "F.Cu" "B.Cu")
		(net "GND")
	)
	(via
		(at 272.273014 -250.016772)
		(size 0.4572)
		(drill 0.2032)
		(layers "F.Cu" "B.Cu")
		(net "GND")
	)
	(via
		(at 396.71625 -407.00452)
		(size 0.4064)
		(drill 0.2032)
		(layers "F.Cu" "B.Cu")
		(net "GND")
	)
	(via
		(at 56.83885 -156.446474)
		(size 0.49022)
		(drill 0.254)
		(layers "F.Cu" "B.Cu")
		(net "GND")
	)
	(via
		(at 56.182514 -221.116652)
		(size 0.4572)
		(drill 0.2032)
		(layers "F.Cu" "B.Cu")
		(net "GND")
	)
	(via
		(at 126.676912 -247.178322)
		(size 0.4572)
		(drill 0.2032)
		(layers "F.Cu" "B.Cu")
		(net "GND")
	)
	(via
		(at 14.426946 -389.151876)
		(size 0.508)
		(drill 0.254)
		(layers "F.Cu" "B.Cu")
		(net "GND")
	)
	(via
		(at 412.964122 -313.766708)
		(size 0.4572)
		(drill 0.2032)
		(layers "F.Cu" "B.Cu")
		(net "GND")
	)
	(via
		(at 11.895836 -91.658948)
		(size 0.508)
		(drill 0.254)
		(layers "F.Cu" "B.Cu")
		(net "GND")
	)
	(via
		(at 344.260678 -354.58908)
		(size 0.508)
		(drill 0.254)
		(layers "F.Cu" "B.Cu")
		(net "GND")
	)
	(via
		(at 48.854614 -303.566576)
		(size 0.4572)
		(drill 0.2032)
		(layers "F.Cu" "B.Cu")
		(net "GND")
	)
	(via
		(at 343.507568 -407.00452)
		(size 0.4064)
		(drill 0.2032)
		(layers "F.Cu" "B.Cu")
		(net "GND")
	)
	(via
		(at 37.940234 -107.539282)
		(size 0.508)
		(drill 0.254)
		(layers "F.Cu" "B.Cu")
		(net "GND")
	)
	(via
		(at 2.764536 -361.110022)
		(size 0.508)
		(drill 0.254)
		(layers "F.Cu" "B.Cu")
		(net "GND")
	)
	(via
		(at 264.729214 -231.316784)
		(size 0.4572)
		(drill 0.2032)
		(layers "F.Cu" "B.Cu")
		(net "GND")
	)
	(via
		(at 378.376434 -222.761556)
		(size 0.4572)
		(drill 0.2032)
		(layers "F.Cu" "B.Cu")
		(net "GND")
	)
	(via
		(at 194.193414 -205.816708)
		(size 0.4572)
		(drill 0.2032)
		(layers "F.Cu" "B.Cu")
		(net "GND")
	)
	(via
		(at 419.502082 -316.316614)
		(size 0.4572)
		(drill 0.2032)
		(layers "F.Cu" "B.Cu")
		(net "GND")
	)
	(via
		(at 22.123146 -225.36658)
		(size 0.4572)
		(drill 0.2032)
		(layers "F.Cu" "B.Cu")
		(net "GND")
	)
	(via
		(at 83.726528 -277.410672)
		(size 0.4572)
		(drill 0.2032)
		(layers "F.Cu" "B.Cu")
		(net "GND")
	)
	(via
		(at 303.281842 -435.585108)
		(size 0.508)
		(drill 0.254)
		(layers "F.Cu" "B.Cu")
		(net "GND")
	)
	(via
		(at 76.250038 -431.451258)
		(size 0.4572)
		(drill 0.2032)
		(layers "F.Cu" "B.Cu")
		(net "GND")
	)
	(via
		(at 349.242634 -222.761556)
		(size 0.4572)
		(drill 0.2032)
		(layers "F.Cu" "B.Cu")
		(net "GND")
	)
	(via
		(at 328.191368 -407.00452)
		(size 0.4064)
		(drill 0.2032)
		(layers "F.Cu" "B.Cu")
		(net "GND")
	)
	(via
		(at 105.641394 -269.38351)
		(size 0.4572)
		(drill 0.2032)
		(layers "F.Cu" "B.Cu")
		(net "GND")
	)
	(via
		(at 2.764536 -295.070022)
		(size 0.508)
		(drill 0.254)
		(layers "F.Cu" "B.Cu")
		(net "GND")
	)
	(via
		(at 337.581748 -43.751246)
		(size 0.4572)
		(drill 0.2032)
		(layers "F.Cu" "B.Cu")
		(net "GND")
	)
	(via
		(at 202.971146 -317.166752)
		(size 0.4572)
		(drill 0.2032)
		(layers "F.Cu" "B.Cu")
		(net "GND")
	)
	(via
		(at 333.845662 -285.661354)
		(size 0.4572)
		(drill 0.2032)
		(layers "F.Cu" "B.Cu")
		(net "GND")
	)
	(via
		(at 279.816814 -204.96657)
		(size 0.4572)
		(drill 0.2032)
		(layers "F.Cu" "B.Cu")
		(net "GND")
	)
	(via
		(at 281.707082 -294.216582)
		(size 0.4572)
		(drill 0.2032)
		(layers "F.Cu" "B.Cu")
		(net "GND")
	)
	(via
		(at 26.223214 -207.51673)
		(size 0.4572)
		(drill 0.2032)
		(layers "F.Cu" "B.Cu")
		(net "GND")
	)
	(via
		(at 125.847348 -258.80314)
		(size 0.4572)
		(drill 0.2032)
		(layers "F.Cu" "B.Cu")
		(net "GND")
	)
	(via
		(at 126.316994 -259.616956)
		(size 0.4572)
		(drill 0.2032)
		(layers "F.Cu" "B.Cu")
		(net "GND")
	)
	(via
		(at 384.46329 -410.030168)
		(size 0.4064)
		(drill 0.2032)
		(layers "F.Cu" "B.Cu")
		(net "GND")
	)
	(via
		(at 384.824478 -406.370536)
		(size 0.4572)
		(drill 0.254)
		(layers "F.Cu" "B.Cu")
		(net "GND")
	)
	(via
		(at 272.273014 -285.716726)
		(size 0.4572)
		(drill 0.2032)
		(layers "F.Cu" "B.Cu")
		(net "GND")
	)
	(via
		(at 13.345414 -277.216616)
		(size 0.4572)
		(drill 0.2032)
		(layers "F.Cu" "B.Cu")
		(net "GND")
	)
	(via
		(at 120.72239 -354.432108)
		(size 0.508)
		(drill 0.254)
		(layers "F.Cu" "B.Cu")
		(net "GND")
	)
	(via
		(at 427.2026 -57.902348)
		(size 0.508)
		(drill 0.254)
		(layers "F.Cu" "B.Cu")
		(net "GND")
	)
	(via
		(at 22.123146 -258.516628)
		(size 0.4572)
		(drill 0.2032)
		(layers "F.Cu" "B.Cu")
		(net "GND")
	)
	(via
		(at 384.350006 -433.747164)
		(size 0.4572)
		(drill 0.2032)
		(layers "F.Cu" "B.Cu")
		(net "GND")
	)
	(via
		(at 44.754546 -197.316598)
		(size 0.4572)
		(drill 0.2032)
		(layers "F.Cu" "B.Cu")
		(net "GND")
	)
	(via
		(at 63.726314 -272.966688)
		(size 0.4572)
		(drill 0.2032)
		(layers "F.Cu" "B.Cu")
		(net "GND")
	)
	(via
		(at 382.135634 -240.667286)
		(size 0.4572)
		(drill 0.2032)
		(layers "F.Cu" "B.Cu")
		(net "GND")
	)
	(via
		(at 194.193414 -196.466714)
		(size 0.4572)
		(drill 0.2032)
		(layers "F.Cu" "B.Cu")
		(net "GND")
	)
	(via
		(at 382.245616 -288.103056)
		(size 0.4572)
		(drill 0.2032)
		(layers "F.Cu" "B.Cu")
		(net "GND")
	)
	(via
		(at 39.420546 -289.11677)
		(size 0.4572)
		(drill 0.2032)
		(layers "F.Cu" "B.Cu")
		(net "GND")
	)
	(via
		(at 427.045882 -310.366664)
		(size 0.4572)
		(drill 0.2032)
		(layers "F.Cu" "B.Cu")
		(net "GND")
	)
	(via
		(at 127.726948 -270.19758)
		(size 0.4572)
		(drill 0.2032)
		(layers "F.Cu" "B.Cu")
		(net "GND")
	)
	(via
		(at 339.374734 -238.225584)
		(size 0.4572)
		(drill 0.2032)
		(layers "F.Cu" "B.Cu")
		(net "GND")
	)
	(via
		(at 121.216166 -404.51786)
		(size 0.4572)
		(drill 0.254)
		(layers "F.Cu" "B.Cu")
		(net "GND")
	)
	(via
		(at 175.005746 -268.71676)
		(size 0.4572)
		(drill 0.2032)
		(layers "F.Cu" "B.Cu")
		(net "GND")
	)
	(via
		(at 336.085434 -224.389442)
		(size 0.4572)
		(drill 0.2032)
		(layers "F.Cu" "B.Cu")
		(net "GND")
	)
	(via
		(at 55.817008 -356.107746)
		(size 0.508)
		(drill 0.254)
		(layers "F.Cu" "B.Cu")
		(net "GND")
	)
	(via
		(at 416.479482 -354.180394)
		(size 0.508)
		(drill 0.254)
		(layers "F.Cu" "B.Cu")
		(net "GND")
	)
	(via
		(at 266.619482 -216.866724)
		(size 0.4572)
		(drill 0.2032)
		(layers "F.Cu" "B.Cu")
		(net "GND")
	)
	(via
		(at 415.639504 -313.766708)
		(size 0.4572)
		(drill 0.2032)
		(layers "F.Cu" "B.Cu")
		(net "GND")
	)
	(via
		(at 115.428522 -256.389886)
		(size 0.4572)
		(drill 0.2032)
		(layers "F.Cu" "B.Cu")
		(net "GND")
	)
	(via
		(at 93.423994 -257.98907)
		(size 0.4572)
		(drill 0.2032)
		(layers "F.Cu" "B.Cu")
		(net "GND")
	)
	(via
		(at 161.808414 -278.916638)
		(size 0.4572)
		(drill 0.2032)
		(layers "F.Cu" "B.Cu")
		(net "GND")
	)
	(via
		(at 449.677282 -286.56661)
		(size 0.4572)
		(drill 0.2032)
		(layers "F.Cu" "B.Cu")
		(net "GND")
	)
	(via
		(at 414.85947 -172.834554)
		(size 0.49022)
		(drill 0.254)
		(layers "F.Cu" "B.Cu")
		(net "GND")
	)
	(via
		(at 63.942214 -262.76681)
		(size 0.4572)
		(drill 0.2032)
		(layers "F.Cu" "B.Cu")
		(net "GND")
	)
	(via
		(at 333.26578 -227.64496)
		(size 0.4572)
		(drill 0.2032)
		(layers "F.Cu" "B.Cu")
		(net "GND")
	)
	(via
		(at 56.398414 -284.866588)
		(size 0.4572)
		(drill 0.2032)
		(layers "F.Cu" "B.Cu")
		(net "GND")
	)
	(via
		(at 373.207534 -223.575626)
		(size 0.4572)
		(drill 0.2032)
		(layers "F.Cu" "B.Cu")
		(net "GND")
	)
	(via
		(at 288.805366 -362.414566)
		(size 0.49022)
		(drill 0.254)
		(layers "F.Cu" "B.Cu")
		(net "GND")
	)
	(via
		(at 325.982838 -51.32959)
		(size 0.49022)
		(drill 0.254)
		(layers "F.Cu" "B.Cu")
		(net "GND")
	)
	(via
		(at 384.594862 -269.38351)
		(size 0.4318)
		(drill 0.2032)
		(layers "F.Cu" "B.Cu")
		(net "GND")
	)
	(via
		(at 92.287598 -403.883876)
		(size 0.4064)
		(drill 0.2032)
		(layers "F.Cu" "B.Cu")
		(net "GND")
	)
	(via
		(at 262.519414 -197.316598)
		(size 0.4572)
		(drill 0.2032)
		(layers "F.Cu" "B.Cu")
		(net "GND")
	)
	(via
		(at 377.436634 -230.900478)
		(size 0.4572)
		(drill 0.2032)
		(layers "F.Cu" "B.Cu")
		(net "GND")
	)
	(via
		(at 442.133482 -278.916638)
		(size 0.4572)
		(drill 0.2032)
		(layers "F.Cu" "B.Cu")
		(net "GND")
	)
	(via
		(at 202.74788 -151.729948)
		(size 0.508)
		(drill 0.254)
		(layers "F.Cu" "B.Cu")
		(net "GND")
	)
	(via
		(at 354.051362 -275.08073)
		(size 0.4572)
		(drill 0.2032)
		(layers "F.Cu" "B.Cu")
		(net "GND")
	)
	(via
		(at 58.233056 -152.936702)
		(size 0.508)
		(drill 0.254)
		(layers "F.Cu" "B.Cu")
		(net "GND")
	)
	(via
		(at 306.548282 -267.866622)
		(size 0.4572)
		(drill 0.2032)
		(layers "F.Cu" "B.Cu")
		(net "GND")
	)
	(via
		(at 254.975614 -290.816792)
		(size 0.4572)
		(drill 0.2032)
		(layers "F.Cu" "B.Cu")
		(net "GND")
	)
	(via
		(at 191.23533 -441.225432)
		(size 0.508)
		(drill 0.254)
		(layers "F.Cu" "B.Cu")
		(net "GND")
	)
	(via
		(at 84.386166 -239.0394)
		(size 0.4572)
		(drill 0.2032)
		(layers "F.Cu" "B.Cu")
		(net "GND")
	)
	(via
		(at 173.632368 -415.250376)
		(size 0.508)
		(drill 0.254)
		(layers "F.Cu" "B.Cu")
		(net "GND")
	)
	(via
		(at 364.389416 -279.964134)
		(size 0.4572)
		(drill 0.2032)
		(layers "F.Cu" "B.Cu")
		(net "GND")
	)
	(via
		(at 169.755566 -122.175524)
		(size 0.4572)
		(drill 0.254)
		(layers "F.Cu" "B.Cu")
		(net "GND")
	)
	(via
		(at 438.033414 -285.716726)
		(size 0.4572)
		(drill 0.2032)
		(layers "F.Cu" "B.Cu")
		(net "GND")
	)
	(via
		(at 453.121014 -197.316598)
		(size 0.4572)
		(drill 0.2032)
		(layers "F.Cu" "B.Cu")
		(net "GND")
	)
	(via
		(at 361.460034 -242.294918)
		(size 0.4572)
		(drill 0.2032)
		(layers "F.Cu" "B.Cu")
		(net "GND")
	)
	(via
		(at 69.224906 -403.249892)
		(size 0.4572)
		(drill 0.254)
		(layers "F.Cu" "B.Cu")
		(net "GND")
	)
	(via
		(at 190.093346 -201.56678)
		(size 0.4572)
		(drill 0.2032)
		(layers "F.Cu" "B.Cu")
		(net "GND")
	)
	(via
		(at 379.769116 -335.980278)
		(size 0.49022)
		(drill 0.254)
		(layers "F.Cu" "B.Cu")
		(net "GND")
	)
	(via
		(at 427.045882 -284.866588)
		(size 0.4572)
		(drill 0.2032)
		(layers "F.Cu" "B.Cu")
		(net "GND")
	)
	(via
		(at 355.461062 -287.28924)
		(size 0.4572)
		(drill 0.2032)
		(layers "F.Cu" "B.Cu")
		(net "GND")
	)
	(via
		(at 168.854628 -351.493328)
		(size 0.508)
		(drill 0.254)
		(layers "F.Cu" "B.Cu")
		(net "GND")
	)
	(via
		(at 31.876746 -273.816572)
		(size 0.4572)
		(drill 0.2032)
		(layers "F.Cu" "B.Cu")
		(net "GND")
	)
	(via
		(at 76.61021 -403.249892)
		(size 0.4572)
		(drill 0.254)
		(layers "F.Cu" "B.Cu")
		(net "GND")
	)
	(via
		(at 331.484224 -337.643216)
		(size 0.508)
		(drill 0.254)
		(layers "F.Cu" "B.Cu")
		(net "GND")
	)
	(via
		(at 339.484462 -256.361438)
		(size 0.4572)
		(drill 0.2032)
		(layers "F.Cu" "B.Cu")
		(net "GND")
	)
	(via
		(at 281.707082 -301.01667)
		(size 0.4572)
		(drill 0.2032)
		(layers "F.Cu" "B.Cu")
		(net "GND")
	)
	(via
		(at 194.39001 -118.074948)
		(size 0.508)
		(drill 0.254)
		(layers "F.Cu" "B.Cu")
		(net "GND")
	)
	(via
		(at 346.570808 -410.030168)
		(size 0.4064)
		(drill 0.2032)
		(layers "F.Cu" "B.Cu")
		(net "GND")
	)
	(via
		(at 108.460794 -279.150318)
		(size 0.4572)
		(drill 0.2032)
		(layers "F.Cu" "B.Cu")
		(net "GND")
	)
	(via
		(at 337.116928 -400.858228)
		(size 0.4064)
		(drill 0.2032)
		(layers "F.Cu" "B.Cu")
		(net "GND")
	)
	(via
		(at 373.405654 -52.768754)
		(size 0.508)
		(drill 0.254)
		(layers "F.Cu" "B.Cu")
		(net "GND")
	)
	(via
		(at 167.690546 -285.716726)
		(size 0.4572)
		(drill 0.2032)
		(layers "F.Cu" "B.Cu")
		(net "GND")
	)
	(via
		(at 366.159034 -229.272846)
		(size 0.4572)
		(drill 0.2032)
		(layers "F.Cu" "B.Cu")
		(net "GND")
	)
	(via
		(at 363.656118 -360.83875)
		(size 0.508)
		(drill 0.254)
		(layers "F.Cu" "B.Cu")
		(net "GND")
	)
	(via
		(at 420.736014 -283.166566)
		(size 0.4572)
		(drill 0.2032)
		(layers "F.Cu" "B.Cu")
		(net "GND")
	)
	(via
		(at 24.332946 -295.06672)
		(size 0.4572)
		(drill 0.2032)
		(layers "F.Cu" "B.Cu")
		(net "GND")
	)
	(via
		(at 54.508146 -199.01662)
		(size 0.4572)
		(drill 0.2032)
		(layers "F.Cu" "B.Cu")
		(net "GND")
	)
	(via
		(at 307.782214 -210.916774)
		(size 0.4572)
		(drill 0.2032)
		(layers "F.Cu" "B.Cu")
		(net "GND")
	)
	(via
		(at 73.54697 -403.249892)
		(size 0.4572)
		(drill 0.254)
		(layers "F.Cu" "B.Cu")
		(net "GND")
	)
	(via
		(at 396.990062 -400.224244)
		(size 0.4572)
		(drill 0.254)
		(layers "F.Cu" "B.Cu")
		(net "GND")
	)
	(via
		(at 311.882282 -222.816674)
		(size 0.4572)
		(drill 0.2032)
		(layers "F.Cu" "B.Cu")
		(net "GND")
	)
	(via
		(at 243.72189 -251.581158)
		(size 0.508)
		(drill 0.254)
		(layers "F.Cu" "B.Cu")
		(net "GND")
	)
	(via
		(at 371.225318 -401.492212)
		(size 0.4572)
		(drill 0.254)
		(layers "F.Cu" "B.Cu")
		(net "GND")
	)
	(via
		(at 435.823614 -258.516628)
		(size 0.4572)
		(drill 0.2032)
		(layers "F.Cu" "B.Cu")
		(net "GND")
	)
	(via
		(at 22.123146 -306.116736)
		(size 0.4572)
		(drill 0.2032)
		(layers "F.Cu" "B.Cu")
		(net "GND")
	)
	(via
		(at 56.83885 -166.555674)
		(size 0.49022)
		(drill 0.254)
		(layers "F.Cu" "B.Cu")
		(net "GND")
	)
	(via
		(at 254.975614 -298.466764)
		(size 0.4572)
		(drill 0.2032)
		(layers "F.Cu" "B.Cu")
		(net "GND")
	)
	(via
		(at 182.549546 -195.616576)
		(size 0.4572)
		(drill 0.2032)
		(layers "F.Cu" "B.Cu")
		(net "GND")
	)
	(via
		(at 134.665466 -217.064336)
		(size 0.4572)
		(drill 0.2032)
		(layers "F.Cu" "B.Cu")
		(net "GND")
	)
	(via
		(at 123.027948 -279.964134)
		(size 0.4572)
		(drill 0.2032)
		(layers "F.Cu" "B.Cu")
		(net "GND")
	)
	(via
		(at 24.332946 -309.51678)
		(size 0.4572)
		(drill 0.2032)
		(layers "F.Cu" "B.Cu")
		(net "GND")
	)
	(via
		(at 104.231694 -283.219906)
		(size 0.4572)
		(drill 0.2032)
		(layers "F.Cu" "B.Cu")
		(net "GND")
	)
	(via
		(at 32.100266 -16.978376)
		(size 0.508)
		(drill 0.254)
		(layers "F.Cu" "B.Cu")
		(net "GND")
	)
	(via
		(at 329.54722 -401.492212)
		(size 0.4572)
		(drill 0.254)
		(layers "F.Cu" "B.Cu")
		(net "GND")
	)
	(via
		(at 340.08314 -406.370536)
		(size 0.4572)
		(drill 0.254)
		(layers "F.Cu" "B.Cu")
		(net "GND")
	)
	(via
		(at 279.816814 -236.416596)
		(size 0.4572)
		(drill 0.2032)
		(layers "F.Cu" "B.Cu")
		(net "GND")
	)
	(via
		(at 126.534926 -123.112784)
		(size 0.508)
		(drill 0.254)
		(layers "F.Cu" "B.Cu")
		(net "GND")
	)
	(via
		(at 202.971146 -236.416596)
		(size 0.4572)
		(drill 0.2032)
		(layers "F.Cu" "B.Cu")
		(net "GND")
	)
	(via
		(at 370.600478 -186.32043)
		(size 0.508)
		(drill 0.254)
		(layers "F.Cu" "B.Cu")
		(net "GND")
	)
	(via
		(at 182.675276 -52.893722)
		(size 0.508)
		(drill 0.254)
		(layers "F.Cu" "B.Cu")
		(net "GND")
	)
	(via
		(at 23.608284 -323.434456)
		(size 0.4572)
		(drill 0.2032)
		(layers "F.Cu" "B.Cu")
		(net "GND")
	)
	(via
		(at 442.133482 -269.566644)
		(size 0.4572)
		(drill 0.2032)
		(layers "F.Cu" "B.Cu")
		(net "GND")
	)
	(via
		(at 180.339746 -236.416596)
		(size 0.4572)
		(drill 0.2032)
		(layers "F.Cu" "B.Cu")
		(net "GND")
	)
	(via
		(at 171.562014 -215.166702)
		(size 0.4572)
		(drill 0.2032)
		(layers "F.Cu" "B.Cu")
		(net "GND")
	)
	(via
		(at 427.045882 -299.316648)
		(size 0.4572)
		(drill 0.2032)
		(layers "F.Cu" "B.Cu")
		(net "GND")
	)
	(via
		(at 194.193414 -306.96662)
		(size 0.4572)
		(drill 0.2032)
		(layers "F.Cu" "B.Cu")
		(net "GND")
	)
	(via
		(at 207.899 -114.7318)
		(size 0.508)
		(drill 0.254)
		(layers "F.Cu" "B.Cu")
		(net "GND")
	)
	(via
		(at 296.794682 -228.766624)
		(size 0.4572)
		(drill 0.2032)
		(layers "F.Cu" "B.Cu")
		(net "GND")
	)
	(via
		(at 58.725562 -151.59228)
		(size 0.508)
		(drill 0.254)
		(layers "F.Cu" "B.Cu")
		(net "GND")
	)
	(via
		(at 317.381636 -406.370536)
		(size 0.4572)
		(drill 0.254)
		(layers "F.Cu" "B.Cu")
		(net "GND")
	)
	(via
		(at 20.889214 -288.266632)
		(size 0.4572)
		(drill 0.2032)
		(layers "F.Cu" "B.Cu")
		(net "GND")
	)
	(via
		(at 33.767014 -312.91657)
		(size 0.4572)
		(drill 0.2032)
		(layers "F.Cu" "B.Cu")
		(net "GND")
	)
	(via
		(at 93.784166 -222.761556)
		(size 0.4572)
		(drill 0.2032)
		(layers "F.Cu" "B.Cu")
		(net "GND")
	)
	(via
		(at 209.281014 -264.466578)
		(size 0.4572)
		(drill 0.2032)
		(layers "F.Cu" "B.Cu")
		(net "GND")
	)
	(via
		(at 43.520614 -224.516696)
		(size 0.4572)
		(drill 0.2032)
		(layers "F.Cu" "B.Cu")
		(net "GND")
	)
	(via
		(at 438.033414 -233.016806)
		(size 0.4572)
		(drill 0.2032)
		(layers "F.Cu" "B.Cu")
		(net "GND")
	)
	(via
		(at 312.51398 -406.370536)
		(size 0.4572)
		(drill 0.254)
		(layers "F.Cu" "B.Cu")
		(net "GND")
	)
	(via
		(at 139.004548 -271.825212)
		(size 0.4572)
		(drill 0.2032)
		(layers "F.Cu" "B.Cu")
		(net "GND")
	)
	(via
		(at 254.975614 -223.666558)
		(size 0.4572)
		(drill 0.2032)
		(layers "F.Cu" "B.Cu")
		(net "GND")
	)
	(via
		(at 131.955794 -284.033722)
		(size 0.4572)
		(drill 0.2032)
		(layers "F.Cu" "B.Cu")
		(net "GND")
	)
	(via
		(at 417.997894 -180.334158)
		(size 0.49022)
		(drill 0.254)
		(layers "F.Cu" "B.Cu")
		(net "GND")
	)
	(via
		(at 134.349998 -427.851316)
		(size 0.4572)
		(drill 0.2032)
		(layers "F.Cu" "B.Cu")
		(net "GND")
	)
	(via
		(at 428.791624 -17.601438)
		(size 0.508)
		(drill 0.254)
		(layers "F.Cu" "B.Cu")
		(net "GND")
	)
	(via
		(at 13.345414 -301.01667)
		(size 0.4572)
		(drill 0.2032)
		(layers "F.Cu" "B.Cu")
		(net "GND")
	)
	(via
		(at 171.992798 -351.614994)
		(size 0.49022)
		(drill 0.254)
		(layers "F.Cu" "B.Cu")
		(net "GND")
	)
	(via
		(at 416.575494 -180.334158)
		(size 0.49022)
		(drill 0.254)
		(layers "F.Cu" "B.Cu")
		(net "GND")
	)
	(via
		(at 243.99748 -129.403348)
		(size 0.508)
		(drill 0.254)
		(layers "F.Cu" "B.Cu")
		(net "GND")
	)
	(via
		(at 261.285482 -215.166702)
		(size 0.4572)
		(drill 0.2032)
		(layers "F.Cu" "B.Cu")
		(net "GND")
	)
	(via
		(at 96.713294 -289.807142)
		(size 0.4572)
		(drill 0.2032)
		(layers "F.Cu" "B.Cu")
		(net "GND")
	)
	(via
		(at 289.250882 -262.76681)
		(size 0.4572)
		(drill 0.2032)
		(layers "F.Cu" "B.Cu")
		(net "GND")
	)
	(via
		(at 96.243394 -271.011396)
		(size 0.4572)
		(drill 0.2032)
		(layers "F.Cu" "B.Cu")
		(net "GND")
	)
	(via
		(at 155.272994 -403.883876)
		(size 0.4064)
		(drill 0.2032)
		(layers "F.Cu" "B.Cu")
		(net "GND")
	)
	(via
		(at 39.420546 -242.3668)
		(size 0.4572)
		(drill 0.2032)
		(layers "F.Cu" "B.Cu")
		(net "GND")
	)
	(via
		(at 194.759326 -35.595052)
		(size 0.508)
		(drill 0.254)
		(layers "F.Cu" "B.Cu")
		(net "GND")
	)
	(via
		(at 40.788082 -19.770344)
		(size 0.508)
		(drill 0.254)
		(layers "F.Cu" "B.Cu")
		(net "GND")
	)
	(via
		(at 58.608214 -308.666642)
		(size 0.4572)
		(drill 0.2032)
		(layers "F.Cu" "B.Cu")
		(net "GND")
	)
	(via
		(at 266.619482 -291.666676)
		(size 0.4572)
		(drill 0.2032)
		(layers "F.Cu" "B.Cu")
		(net "GND")
	)
	(via
		(at 399.349976 -438.651396)
		(size 0.4572)
		(drill 0.2032)
		(layers "F.Cu" "B.Cu")
		(net "GND")
	)
	(via
		(at 176.896014 -235.566712)
		(size 0.4572)
		(drill 0.2032)
		(layers "F.Cu" "B.Cu")
		(net "GND")
	)
	(via
		(at 14.579346 -258.516628)
		(size 0.4572)
		(drill 0.2032)
		(layers "F.Cu" "B.Cu")
		(net "GND")
	)
	(via
		(at 382.715516 -282.405836)
		(size 0.4572)
		(drill 0.2032)
		(layers "F.Cu" "B.Cu")
		(net "GND")
	)
	(via
		(at 423.195242 -391.632948)
		(size 0.508)
		(drill 0.254)
		(layers "F.Cu" "B.Cu")
		(net "GND")
	)
	(via
		(at 168.219628 -352.153728)
		(size 0.508)
		(drill 0.254)
		(layers "F.Cu" "B.Cu")
		(net "GND")
	)
	(via
		(at 2.764536 -310.310022)
		(size 0.508)
		(drill 0.254)
		(layers "F.Cu" "B.Cu")
		(net "GND")
	)
	(via
		(at 342.664034 -235.783882)
		(size 0.4572)
		(drill 0.2032)
		(layers "F.Cu" "B.Cu")
		(net "GND")
	)
	(via
		(at 205.180946 -307.816758)
		(size 0.4572)
		(drill 0.2032)
		(layers "F.Cu" "B.Cu")
		(net "GND")
	)
	(via
		(at 346.149422 -36.896548)
		(size 0.49022)
		(drill 0.254)
		(layers "F.Cu" "B.Cu")
		(net "GND")
	)
	(via
		(at 364.389162 -275.08073)
		(size 0.4572)
		(drill 0.2032)
		(layers "F.Cu" "B.Cu")
		(net "GND")
	)
	(via
		(at 418.520118 -409.396184)
		(size 0.4572)
		(drill 0.254)
		(layers "F.Cu" "B.Cu")
		(net "GND")
	)
	(via
		(at 87.205058 -216.25052)
		(size 0.4572)
		(drill 0.2032)
		(layers "F.Cu" "B.Cu")
		(net "GND")
	)
	(via
		(at 344.956892 -333.355188)
		(size 0.49022)
		(drill 0.254)
		(layers "F.Cu" "B.Cu")
		(net "GND")
	)
	(via
		(at 315.57722 -407.638504)
		(size 0.4572)
		(drill 0.254)
		(layers "F.Cu" "B.Cu")
		(net "GND")
	)
	(via
		(at 445.577214 -258.516628)
		(size 0.4572)
		(drill 0.2032)
		(layers "F.Cu" "B.Cu")
		(net "GND")
	)
	(via
		(at 26.223214 -286.56661)
		(size 0.4572)
		(drill 0.2032)
		(layers "F.Cu" "B.Cu")
		(net "GND")
	)
	(via
		(at 431.36693 -9.424924)
		(size 0.508)
		(drill 0.254)
		(layers "F.Cu" "B.Cu")
		(net "GND")
	)
	(via
		(at 148.872702 -407.638504)
		(size 0.4572)
		(drill 0.254)
		(layers "F.Cu" "B.Cu")
		(net "GND")
	)
	(via
		(at 457.221082 -241.516662)
		(size 0.4572)
		(drill 0.2032)
		(layers "F.Cu" "B.Cu")
		(net "GND")
	)
	(via
		(at 327.96607 -341.85225)
		(size 0.49022)
		(drill 0.254)
		(layers "F.Cu" "B.Cu")
		(net "GND")
	)
	(via
		(at 180.838602 -354.115878)
		(size 0.49022)
		(drill 0.254)
		(layers "F.Cu" "B.Cu")
		(net "GND")
	)
	(via
		(at 76.105512 -37.897562)
		(size 0.508)
		(drill 0.254)
		(layers "F.Cu" "B.Cu")
		(net "GND")
	)
	(via
		(at 132.210302 -404.51786)
		(size 0.4572)
		(drill 0.254)
		(layers "F.Cu" "B.Cu")
		(net "GND")
	)
	(via
		(at 383.38125 -410.030168)
		(size 0.4064)
		(drill 0.2032)
		(layers "F.Cu" "B.Cu")
		(net "GND")
	)
	(via
		(at 132.425694 -262.058658)
		(size 0.4572)
		(drill 0.2032)
		(layers "F.Cu" "B.Cu")
		(net "GND")
	)
	(via
		(at 83.770978 -243.48313)
		(size 0.6604)
		(drill 0.3302)
		(layers "F.Cu" "B.Cu")
		(net "GND")
	)
	(via
		(at 186.649614 -264.466578)
		(size 0.4572)
		(drill 0.2032)
		(layers "F.Cu" "B.Cu")
		(net "GND")
	)
	(via
		(at 264.729214 -306.116736)
		(size 0.4572)
		(drill 0.2032)
		(layers "F.Cu" "B.Cu")
		(net "GND")
	)
	(via
		(at 201.737214 -266.1666)
		(size 0.4572)
		(drill 0.2032)
		(layers "F.Cu" "B.Cu")
		(net "GND")
	)
	(via
		(at 165.252146 -267.016738)
		(size 0.4572)
		(drill 0.2032)
		(layers "F.Cu" "B.Cu")
		(net "GND")
	)
	(via
		(at 325.702422 -63.236348)
		(size 0.508)
		(drill 0.254)
		(layers "F.Cu" "B.Cu")
		(net "GND")
	)
	(via
		(at 33.767014 -207.51673)
		(size 0.4572)
		(drill 0.2032)
		(layers "F.Cu" "B.Cu")
		(net "GND")
	)
	(via
		(at 338.904834 -229.272846)
		(size 0.4572)
		(drill 0.2032)
		(layers "F.Cu" "B.Cu")
		(net "GND")
	)
	(via
		(at 395.13129 -4.317746)
		(size 0.508)
		(drill 0.254)
		(layers "F.Cu" "B.Cu")
		(net "GND")
	)
	(via
		(at 194.193414 -269.566644)
		(size 0.4572)
		(drill 0.2032)
		(layers "F.Cu" "B.Cu")
		(net "GND")
	)
	(via
		(at 395.273022 -407.638504)
		(size 0.4572)
		(drill 0.254)
		(layers "F.Cu" "B.Cu")
		(net "GND")
	)
	(via
		(at 438.654952 -394.876274)
		(size 0.6604)
		(drill 0.3302)
		(layers "F.Cu" "B.Cu")
		(net "GND")
	)
	(via
		(at 104.701594 -266.128246)
		(size 0.4572)
		(drill 0.2032)
		(layers "F.Cu" "B.Cu")
		(net "GND")
	)
	(via
		(at 137.954766 -235.783882)
		(size 0.4318)
		(drill 0.2032)
		(layers "F.Cu" "B.Cu")
		(net "GND")
	)
	(via
		(at 66.152014 -198.166736)
		(size 0.4572)
		(drill 0.2032)
		(layers "F.Cu" "B.Cu")
		(net "GND")
	)
	(via
		(at 180.339746 -292.516814)
		(size 0.4572)
		(drill 0.2032)
		(layers "F.Cu" "B.Cu")
		(net "GND")
	)
	(via
		(at 161.125662 -410.664152)
		(size 0.4572)
		(drill 0.254)
		(layers "F.Cu" "B.Cu")
		(net "GND")
	)
	(via
		(at 187.883546 -311.216802)
		(size 0.4572)
		(drill 0.2032)
		(layers "F.Cu" "B.Cu")
		(net "GND")
	)
	(via
		(at 115.869466 -213.732618)
		(size 0.4572)
		(drill 0.2032)
		(layers "F.Cu" "B.Cu")
		(net "GND")
	)
	(via
		(at 23.113492 -384.311398)
		(size 0.508)
		(drill 0.254)
		(layers "F.Cu" "B.Cu")
		(net "GND")
	)
	(via
		(at 424.836082 -235.566712)
		(size 0.4572)
		(drill 0.2032)
		(layers "F.Cu" "B.Cu")
		(net "GND")
	)
	(via
		(at 457.227178 -319.132204)
		(size 0.508)
		(drill 0.254)
		(layers "F.Cu" "B.Cu")
		(net "GND")
	)
	(via
		(at 44.840906 -18.246344)
		(size 0.508)
		(drill 0.254)
		(layers "F.Cu" "B.Cu")
		(net "GND")
	)
	(via
		(at 373.207534 -230.086662)
		(size 0.4572)
		(drill 0.2032)
		(layers "F.Cu" "B.Cu")
		(net "GND")
	)
	(via
		(at 159.918146 -246.616728)
		(size 0.4572)
		(drill 0.2032)
		(layers "F.Cu" "B.Cu")
		(net "GND")
	)
	(via
		(at 332.435962 -258.80314)
		(size 0.4572)
		(drill 0.2032)
		(layers "F.Cu" "B.Cu")
		(net "GND")
	)
	(via
		(at 130.350006 -433.899564)
		(size 0.4572)
		(drill 0.2032)
		(layers "F.Cu" "B.Cu")
		(net "GND")
	)
	(via
		(at 122.557794 -254.733552)
		(size 0.4572)
		(drill 0.2032)
		(layers "F.Cu" "B.Cu")
		(net "GND")
	)
	(via
		(at 43.520614 -303.566576)
		(size 0.4572)
		(drill 0.2032)
		(layers "F.Cu" "B.Cu")
		(net "GND")
	)
	(via
		(at 445.577214 -309.51678)
		(size 0.4572)
		(drill 0.2032)
		(layers "F.Cu" "B.Cu")
		(net "GND")
	)
	(via
		(at 426.595032 -381.868934)
		(size 0.508)
		(drill 0.254)
		(layers "F.Cu" "B.Cu")
		(net "GND")
	)
	(via
		(at 254.975614 -240.666778)
		(size 0.4572)
		(drill 0.2032)
		(layers "F.Cu" "B.Cu")
		(net "GND")
	)
	(via
		(at 131.016248 -277.522432)
		(size 0.4572)
		(drill 0.2032)
		(layers "F.Cu" "B.Cu")
		(net "GND")
	)
	(via
		(at 180.339746 -272.116804)
		(size 0.4572)
		(drill 0.2032)
		(layers "F.Cu" "B.Cu")
		(net "GND")
	)
	(via
		(at 88.615266 -225.203258)
		(size 0.4572)
		(drill 0.2032)
		(layers "F.Cu" "B.Cu")
		(net "GND")
	)
	(via
		(at 92.844366 -232.528364)
		(size 0.4572)
		(drill 0.2032)
		(layers "F.Cu" "B.Cu")
		(net "GND")
	)
	(via
		(at 56.195214 -235.566712)
		(size 0.4572)
		(drill 0.2032)
		(layers "F.Cu" "B.Cu")
		(net "GND")
	)
	(via
		(at 270.063214 -212.616796)
		(size 0.4572)
		(drill 0.2032)
		(layers "F.Cu" "B.Cu")
		(net "GND")
	)
	(via
		(at 257.185414 -216.016586)
		(size 0.4572)
		(drill 0.2032)
		(layers "F.Cu" "B.Cu")
		(net "GND")
	)
	(via
		(at 124.437394 -279.150318)
		(size 0.4572)
		(drill 0.2032)
		(layers "F.Cu" "B.Cu")
		(net "GND")
	)
	(via
		(at 277.607014 -201.56678)
		(size 0.4572)
		(drill 0.2032)
		(layers "F.Cu" "B.Cu")
		(net "GND")
	)
	(via
		(at 33.767014 -275.516594)
		(size 0.4572)
		(drill 0.2032)
		(layers "F.Cu" "B.Cu")
		(net "GND")
	)
	(via
		(at 279.816814 -301.866808)
		(size 0.4572)
		(drill 0.2032)
		(layers "F.Cu" "B.Cu")
		(net "GND")
	)
	(via
		(at 59.842146 -203.266802)
		(size 0.4572)
		(drill 0.2032)
		(layers "F.Cu" "B.Cu")
		(net "GND")
	)
	(via
		(at 167.461946 -260.21665)
		(size 0.4572)
		(drill 0.2032)
		(layers "F.Cu" "B.Cu")
		(net "GND")
	)
	(via
		(at 385.064762 -279.964134)
		(size 0.4572)
		(drill 0.2032)
		(layers "F.Cu" "B.Cu")
		(net "GND")
	)
	(via
		(at 365.888778 -330.91882)
		(size 0.508)
		(drill 0.254)
		(layers "F.Cu" "B.Cu")
		(net "GND")
	)
	(via
		(at 186.649614 -310.366664)
		(size 0.4572)
		(drill 0.2032)
		(layers "F.Cu" "B.Cu")
		(net "GND")
	)
	(via
		(at 455.011282 -247.466612)
		(size 0.4572)
		(drill 0.2032)
		(layers "F.Cu" "B.Cu")
		(net "GND")
	)
	(via
		(at 416.179762 -361.726734)
		(size 0.49022)
		(drill 0.254)
		(layers "F.Cu" "B.Cu")
		(net "GND")
	)
	(via
		(at 106.111294 -275.08073)
		(size 0.4572)
		(drill 0.2032)
		(layers "F.Cu" "B.Cu")
		(net "GND")
	)
	(via
		(at 212.724746 -281.466798)
		(size 0.4572)
		(drill 0.2032)
		(layers "F.Cu" "B.Cu")
		(net "GND")
	)
	(via
		(at 337.0199 -407.638504)
		(size 0.4572)
		(drill 0.254)
		(layers "F.Cu" "B.Cu")
		(net "GND")
	)
	(via
		(at 439.923682 -222.816674)
		(size 0.4572)
		(drill 0.2032)
		(layers "F.Cu" "B.Cu")
		(net "GND")
	)
	(via
		(at 137.124694 -258.80314)
		(size 0.4318)
		(drill 0.2032)
		(layers "F.Cu" "B.Cu")
		(net "GND")
	)
	(via
		(at 457.221082 -226.216718)
		(size 0.4572)
		(drill 0.2032)
		(layers "F.Cu" "B.Cu")
		(net "GND")
	)
	(via
		(at 332.697836 -406.370536)
		(size 0.4572)
		(drill 0.254)
		(layers "F.Cu" "B.Cu")
		(net "GND")
	)
	(via
		(at 102.242366 -226.017328)
		(size 0.4572)
		(drill 0.2032)
		(layers "F.Cu" "B.Cu")
		(net "GND")
	)
	(via
		(at 314.092082 -261.066788)
		(size 0.4572)
		(drill 0.2032)
		(layers "F.Cu" "B.Cu")
		(net "GND")
	)
	(via
		(at 248.76252 -94.762828)
		(size 0.508)
		(drill 0.254)
		(layers "F.Cu" "B.Cu")
		(net "GND")
	)
	(via
		(at 414.677352 -323.429376)
		(size 0.4572)
		(drill 0.2032)
		(layers "F.Cu" "B.Cu")
		(net "GND")
	)
	(via
		(at 339.484716 -274.266914)
		(size 0.4572)
		(drill 0.2032)
		(layers "F.Cu" "B.Cu")
		(net "GND")
	)
	(via
		(at 377.546616 -271.825212)
		(size 0.4572)
		(drill 0.2032)
		(layers "F.Cu" "B.Cu")
		(net "GND")
	)
	(via
		(at 296.794682 -205.816708)
		(size 0.4572)
		(drill 0.2032)
		(layers "F.Cu" "B.Cu")
		(net "GND")
	)
	(via
		(at 164.101526 -404.51786)
		(size 0.4572)
		(drill 0.254)
		(layers "F.Cu" "B.Cu")
		(net "GND")
	)
	(via
		(at 260.27888 -65.954148)
		(size 0.6604)
		(drill 0.3302)
		(layers "F.Cu" "B.Cu")
		(net "GND")
	)
	(via
		(at 254.975614 -279.766776)
		(size 0.4572)
		(drill 0.2032)
		(layers "F.Cu" "B.Cu")
		(net "GND")
	)
	(via
		(at 100.472494 -289.807142)
		(size 0.4572)
		(drill 0.2032)
		(layers "F.Cu" "B.Cu")
		(net "GND")
	)
	(via
		(at 281.707082 -295.916604)
		(size 0.4572)
		(drill 0.2032)
		(layers "F.Cu" "B.Cu")
		(net "GND")
	)
	(via
		(at 88.86317 -403.249892)
		(size 0.4572)
		(drill 0.254)
		(layers "F.Cu" "B.Cu")
		(net "GND")
	)
	(via
		(at 143.506952 -30.14218)
		(size 0.508)
		(drill 0.254)
		(layers "F.Cu" "B.Cu")
		(net "GND")
	)
	(via
		(at 434.092858 -166.405814)
		(size 0.508)
		(drill 0.254)
		(layers "F.Cu" "B.Cu")
		(net "GND")
	)
	(via
		(at 302.448214 -283.166566)
		(size 0.4572)
		(drill 0.2032)
		(layers "F.Cu" "B.Cu")
		(net "GND")
	)
	(via
		(at 99.422966 -232.528364)
		(size 0.4572)
		(drill 0.2032)
		(layers "F.Cu" "B.Cu")
		(net "GND")
	)
	(via
		(at 120.787414 -331.776832)
		(size 0.49022)
		(drill 0.254)
		(layers "F.Cu" "B.Cu")
		(net "GND")
	)
	(via
		(at 331.484224 -340.284816)
		(size 0.508)
		(drill 0.254)
		(layers "F.Cu" "B.Cu")
		(net "GND")
	)
	(via
		(at 376.026934 -226.831144)
		(size 0.4572)
		(drill 0.2032)
		(layers "F.Cu" "B.Cu")
		(net "GND")
	)
	(via
		(at 44.754546 -298.466764)
		(size 0.4572)
		(drill 0.2032)
		(layers "F.Cu" "B.Cu")
		(net "GND")
	)
	(via
		(at 190.093346 -229.616762)
		(size 0.4572)
		(drill 0.2032)
		(layers "F.Cu" "B.Cu")
		(net "GND")
	)
	(via
		(at 345.593416 -279.964134)
		(size 0.4572)
		(drill 0.2032)
		(layers "F.Cu" "B.Cu")
		(net "GND")
	)
	(via
		(at 57.572656 -144.300702)
		(size 0.508)
		(drill 0.254)
		(layers "F.Cu" "B.Cu")
		(net "GND")
	)
	(via
		(at 112.442498 -335.704434)
		(size 0.49022)
		(drill 0.254)
		(layers "F.Cu" "B.Cu")
		(net "GND")
	)
	(via
		(at 464.764882 -205.816708)
		(size 0.4572)
		(drill 0.2032)
		(layers "F.Cu" "B.Cu")
		(net "GND")
	)
	(via
		(at 449.677282 -204.116686)
		(size 0.4572)
		(drill 0.2032)
		(layers "F.Cu" "B.Cu")
		(net "GND")
	)
	(via
		(at 335.725262 -284.033722)
		(size 0.4572)
		(drill 0.2032)
		(layers "F.Cu" "B.Cu")
		(net "GND")
	)
	(via
		(at 78.250034 -431.29962)
		(size 0.4572)
		(drill 0.2032)
		(layers "F.Cu" "B.Cu")
		(net "GND")
	)
	(via
		(at 210.514946 -217.716608)
		(size 0.4572)
		(drill 0.2032)
		(layers "F.Cu" "B.Cu")
		(net "GND")
	)
	(via
		(at 178.289204 -45.299884)
		(size 0.508)
		(drill 0.254)
		(layers "F.Cu" "B.Cu")
		(net "GND")
	)
	(via
		(at 384.594862 -280.778204)
		(size 0.4572)
		(drill 0.2032)
		(layers "F.Cu" "B.Cu")
		(net "GND")
	)
	(via
		(at 442.133482 -310.366664)
		(size 0.4572)
		(drill 0.2032)
		(layers "F.Cu" "B.Cu")
		(net "GND")
	)
	(via
		(at 52.298346 -214.316564)
		(size 0.4572)
		(drill 0.2032)
		(layers "F.Cu" "B.Cu")
		(net "GND")
	)
	(via
		(at 435.823614 -233.016806)
		(size 0.4572)
		(drill 0.2032)
		(layers "F.Cu" "B.Cu")
		(net "GND")
	)
	(via
		(at 115.508278 -331.780896)
		(size 0.49022)
		(drill 0.254)
		(layers "F.Cu" "B.Cu")
		(net "GND")
	)
	(via
		(at 314.092082 -269.566644)
		(size 0.4572)
		(drill 0.2032)
		(layers "F.Cu" "B.Cu")
		(net "GND")
	)
	(via
		(at 377.076462 -274.266914)
		(size 0.4572)
		(drill 0.2032)
		(layers "F.Cu" "B.Cu")
		(net "GND")
	)
	(via
		(at 420.736014 -231.316784)
		(size 0.4572)
		(drill 0.2032)
		(layers "F.Cu" "B.Cu")
		(net "GND")
	)
	(via
		(at 283.916882 -194.766692)
		(size 0.4572)
		(drill 0.2032)
		(layers "F.Cu" "B.Cu")
		(net "GND")
	)
	(via
		(at 342.14181 -339.312504)
		(size 0.508)
		(drill 0.254)
		(layers "F.Cu" "B.Cu")
		(net "GND")
	)
	(via
		(at 52.409598 -322.25488)
		(size 0.4572)
		(drill 0.2032)
		(layers "F.Cu" "B.Cu")
		(net "GND")
	)
	(via
		(at 280.02992 -33.965388)
		(size 0.508)
		(drill 0.254)
		(layers "F.Cu" "B.Cu")
		(net "GND")
	)
	(via
		(at 349.352616 -262.058658)
		(size 0.4572)
		(drill 0.2032)
		(layers "F.Cu" "B.Cu")
		(net "GND")
	)
	(via
		(at 358.280462 -261.244842)
		(size 0.4572)
		(drill 0.2032)
		(layers "F.Cu" "B.Cu")
		(net "GND")
	)
	(via
		(at 406.179782 -400.224244)
		(size 0.4572)
		(drill 0.254)
		(layers "F.Cu" "B.Cu")
		(net "GND")
	)
	(via
		(at 93.730826 -400.224244)
		(size 0.4572)
		(drill 0.254)
		(layers "F.Cu" "B.Cu")
		(net "GND")
	)
	(via
		(at 428.279814 -234.716574)
		(size 0.4572)
		(drill 0.2032)
		(layers "F.Cu" "B.Cu")
		(net "GND")
	)
	(via
		(at 124.437394 -274.266914)
		(size 0.4572)
		(drill 0.2032)
		(layers "F.Cu" "B.Cu")
		(net "GND")
	)
	(via
		(at 24.332946 -212.616796)
		(size 0.4572)
		(drill 0.2032)
		(layers "F.Cu" "B.Cu")
		(net "GND")
	)
	(via
		(at 54.508146 -315.46673)
		(size 0.4572)
		(drill 0.2032)
		(layers "F.Cu" "B.Cu")
		(net "GND")
	)
	(via
		(at 416.556952 -7.215124)
		(size 0.508)
		(drill 0.254)
		(layers "F.Cu" "B.Cu")
		(net "GND")
	)
	(via
		(at 413.192214 -212.616796)
		(size 0.4572)
		(drill 0.2032)
		(layers "F.Cu" "B.Cu")
		(net "GND")
	)
	(via
		(at 262.519414 -298.466764)
		(size 0.4572)
		(drill 0.2032)
		(layers "F.Cu" "B.Cu")
		(net "GND")
	)
	(via
		(at 423.564558 -367.67643)
		(size 0.508)
		(drill 0.254)
		(layers "F.Cu" "B.Cu")
		(net "GND")
	)
	(via
		(at 443.367414 -265.316716)
		(size 0.4572)
		(drill 0.2032)
		(layers "F.Cu" "B.Cu")
		(net "GND")
	)
	(via
		(at 7.035546 -248.31675)
		(size 0.4572)
		(drill 0.2032)
		(layers "F.Cu" "B.Cu")
		(net "GND")
	)
	(via
		(at 405.421338 -216.016586)
		(size 0.4572)
		(drill 0.2032)
		(layers "F.Cu" "B.Cu")
		(net "GND")
	)
	(via
		(at 164.018214 -202.416664)
		(size 0.4572)
		(drill 0.2032)
		(layers "F.Cu" "B.Cu")
		(net "GND")
	)
	(via
		(at 272.273014 -229.616762)
		(size 0.4572)
		(drill 0.2032)
		(layers "F.Cu" "B.Cu")
		(net "GND")
	)
	(via
		(at 126.316994 -275.8948)
		(size 0.4572)
		(drill 0.2032)
		(layers "F.Cu" "B.Cu")
		(net "GND")
	)
	(via
		(at 321.800728 -400.858228)
		(size 0.4064)
		(drill 0.2032)
		(layers "F.Cu" "B.Cu")
		(net "GND")
	)
	(via
		(at 130.350006 -435.0512)
		(size 0.4572)
		(drill 0.2032)
		(layers "F.Cu" "B.Cu")
		(net "GND")
	)
	(via
		(at 92.954348 -266.941808)
		(size 0.4572)
		(drill 0.2032)
		(layers "F.Cu" "B.Cu")
		(net "GND")
	)
	(via
		(at 292.694614 -204.96657)
		(size 0.4572)
		(drill 0.2032)
		(layers "F.Cu" "B.Cu")
		(net "GND")
	)
	(via
		(at 179.03952 -33.945322)
		(size 0.508)
		(drill 0.254)
		(layers "F.Cu" "B.Cu")
		(net "GND")
	)
	(via
		(at 125.722634 -400.858228)
		(size 0.4064)
		(drill 0.2032)
		(layers "F.Cu" "B.Cu")
		(net "GND")
	)
	(via
		(at 102.060248 -410.579824)
		(size 0.508)
		(drill 0.254)
		(layers "F.Cu" "B.Cu")
		(net "GND")
	)
	(via
		(at 20.889214 -196.466714)
		(size 0.4572)
		(drill 0.2032)
		(layers "F.Cu" "B.Cu")
		(net "GND")
	)
	(via
		(at 102.900988 -244.753384)
		(size 0.4572)
		(drill 0.2032)
		(layers "F.Cu" "B.Cu")
		(net "GND")
	)
	(via
		(at 274.163282 -250.866656)
		(size 0.4572)
		(drill 0.2032)
		(layers "F.Cu" "B.Cu")
		(net "GND")
	)
	(via
		(at 412.18358 -176.367948)
		(size 0.508)
		(drill 0.254)
		(layers "F.Cu" "B.Cu")
		(net "GND")
	)
	(via
		(at 33.767014 -247.466612)
		(size 0.4572)
		(drill 0.2032)
		(layers "F.Cu" "B.Cu")
		(net "GND")
	)
	(via
		(at 185.240676 -350.261682)
		(size 0.508)
		(drill 0.254)
		(layers "F.Cu" "B.Cu")
		(net "GND")
	)
	(via
		(at 432.379882 -249.166634)
		(size 0.4572)
		(drill 0.2032)
		(layers "F.Cu" "B.Cu")
		(net "GND")
	)
	(via
		(at 422.945814 -233.016806)
		(size 0.4572)
		(drill 0.2032)
		(layers "F.Cu" "B.Cu")
		(net "GND")
	)
	(via
		(at 386.944616 -271.825212)
		(size 0.4572)
		(drill 0.2032)
		(layers "F.Cu" "B.Cu")
		(net "GND")
	)
	(via
		(at 63.942214 -205.816708)
		(size 0.4572)
		(drill 0.2032)
		(layers "F.Cu" "B.Cu")
		(net "GND")
	)
	(via
		(at 36.110164 -124.67209)
		(size 0.508)
		(drill 0.254)
		(layers "F.Cu" "B.Cu")
		(net "GND")
	)
	(via
		(at 122.917966 -230.900478)
		(size 0.4572)
		(drill 0.2032)
		(layers "F.Cu" "B.Cu")
		(net "GND")
	)
	(via
		(at 368.618262 -284.033722)
		(size 0.4572)
		(drill 0.2032)
		(layers "F.Cu" "B.Cu")
		(net "GND")
	)
	(via
		(at 387.181852 -340.977728)
		(size 0.49022)
		(drill 0.254)
		(layers "F.Cu" "B.Cu")
		(net "GND")
	)
	(via
		(at 392.34999 -439.651394)
		(size 0.4572)
		(drill 0.2032)
		(layers "F.Cu" "B.Cu")
		(net "GND")
	)
	(via
		(at 467.535514 -119.24538)
		(size 0.508)
		(drill 0.254)
		(layers "F.Cu" "B.Cu")
		(net "GND")
	)
	(via
		(at 41.310814 -207.51673)
		(size 0.4572)
		(drill 0.2032)
		(layers "F.Cu" "B.Cu")
		(net "GND")
	)
	(via
		(at 363.063028 -46.802802)
		(size 0.508)
		(drill 0.254)
		(layers "F.Cu" "B.Cu")
		(net "GND")
	)
	(via
		(at 333.507842 -50.799746)
		(size 0.4572)
		(drill 0.2032)
		(layers "F.Cu" "B.Cu")
		(net "GND")
	)
	(via
		(at 37.358066 -183.30164)
		(size 0.508)
		(drill 0.254)
		(layers "F.Cu" "B.Cu")
		(net "GND")
	)
	(via
		(at 171.15028 -355.538278)
		(size 0.49022)
		(drill 0.254)
		(layers "F.Cu" "B.Cu")
		(net "GND")
	)
	(via
		(at 111.170466 -228.45903)
		(size 0.4572)
		(drill 0.2032)
		(layers "F.Cu" "B.Cu")
		(net "GND")
	)
	(via
		(at 367.208816 -278.336502)
		(size 0.4572)
		(drill 0.2032)
		(layers "F.Cu" "B.Cu")
		(net "GND")
	)
	(via
		(at 90.4875 -54.950868)
		(size 0.508)
		(drill 0.254)
		(layers "F.Cu" "B.Cu")
		(net "GND")
	)
	(via
		(at 191.983614 -205.816708)
		(size 0.4572)
		(drill 0.2032)
		(layers "F.Cu" "B.Cu")
		(net "GND")
	)
	(via
		(at 288.545016 -367.755932)
		(size 0.508)
		(drill 0.254)
		(layers "F.Cu" "B.Cu")
		(net "GND")
	)
	(via
		(at 367.098834 -216.25052)
		(size 0.4572)
		(drill 0.2032)
		(layers "F.Cu" "B.Cu")
		(net "GND")
	)
	(via
		(at 19.89709 -19.13636)
		(size 0.508)
		(drill 0.254)
		(layers "F.Cu" "B.Cu")
		(net "GND")
	)
	(via
		(at 25.92324 -125.368812)
		(size 0.508)
		(drill 0.254)
		(layers "F.Cu" "B.Cu")
		(net "GND")
	)
	(via
		(at 407.346404 -50.307494)
		(size 0.508)
		(drill 0.254)
		(layers "F.Cu" "B.Cu")
		(net "GND")
	)
	(via
		(at 121.303542 -410.664152)
		(size 0.4572)
		(drill 0.254)
		(layers "F.Cu" "B.Cu")
		(net "GND")
	)
	(via
		(at 105.17759 -333.355188)
		(size 0.49022)
		(drill 0.254)
		(layers "F.Cu" "B.Cu")
		(net "GND")
	)
	(via
		(at 59.842146 -298.466764)
		(size 0.4572)
		(drill 0.2032)
		(layers "F.Cu" "B.Cu")
		(net "GND")
	)
	(via
		(at 11.135614 -215.166702)
		(size 0.4572)
		(drill 0.2032)
		(layers "F.Cu" "B.Cu")
		(net "GND")
	)
	(via
		(at 80.034638 -400.858228)
		(size 0.4064)
		(drill 0.2032)
		(layers "F.Cu" "B.Cu")
		(net "GND")
	)
	(via
		(at 92.844366 -222.761556)
		(size 0.4572)
		(drill 0.2032)
		(layers "F.Cu" "B.Cu")
		(net "GND")
	)
	(via
		(at 375.547382 -404.51786)
		(size 0.4572)
		(drill 0.254)
		(layers "F.Cu" "B.Cu")
		(net "GND")
	)
	(via
		(at 122.917712 -248.806208)
		(size 0.4572)
		(drill 0.2032)
		(layers "F.Cu" "B.Cu")
		(net "GND")
	)
	(via
		(at 59.737244 -313.684158)
		(size 0.4572)
		(drill 0.2032)
		(layers "F.Cu" "B.Cu")
		(net "GND")
	)
	(via
		(at 462.555082 -241.516662)
		(size 0.4572)
		(drill 0.2032)
		(layers "F.Cu" "B.Cu")
		(net "GND")
	)
	(via
		(at 375.566686 -12.544552)
		(size 0.508)
		(drill 0.254)
		(layers "F.Cu" "B.Cu")
		(net "GND")
	)
	(via
		(at 277.607014 -283.166566)
		(size 0.4572)
		(drill 0.2032)
		(layers "F.Cu" "B.Cu")
		(net "GND")
	)
	(via
		(at 38.45687 -12.37488)
		(size 0.508)
		(drill 0.254)
		(layers "F.Cu" "B.Cu")
		(net "GND")
	)
	(via
		(at 102.712266 -217.064336)
		(size 0.4572)
		(drill 0.2032)
		(layers "F.Cu" "B.Cu")
		(net "GND")
	)
	(via
		(at 413.192214 -279.766776)
		(size 0.4572)
		(drill 0.2032)
		(layers "F.Cu" "B.Cu")
		(net "GND")
	)
	(via
		(at 191.983614 -228.766624)
		(size 0.4572)
		(drill 0.2032)
		(layers "F.Cu" "B.Cu")
		(net "GND")
	)
	(via
		(at 400.41449 -403.883876)
		(size 0.4064)
		(drill 0.2032)
		(layers "F.Cu" "B.Cu")
		(net "GND")
	)
	(via
		(at 257.185414 -304.416714)
		(size 0.4572)
		(drill 0.2032)
		(layers "F.Cu" "B.Cu")
		(net "GND")
	)
	(via
		(at 145.722086 -404.51786)
		(size 0.4572)
		(drill 0.254)
		(layers "F.Cu" "B.Cu")
		(net "GND")
	)
	(via
		(at 314.092082 -241.516662)
		(size 0.4572)
		(drill 0.2032)
		(layers "F.Cu" "B.Cu")
		(net "GND")
	)
	(via
		(at 366.372902 -246.659146)
		(size 0.4572)
		(drill 0.2032)
		(layers "F.Cu" "B.Cu")
		(net "GND")
	)
	(via
		(at 344.25001 -433.899564)
		(size 0.4572)
		(drill 0.2032)
		(layers "F.Cu" "B.Cu")
		(net "GND")
	)
	(via
		(at 423.149014 -311.216802)
		(size 0.4572)
		(drill 0.2032)
		(layers "F.Cu" "B.Cu")
		(net "GND")
	)
	(via
		(at 41.249092 -345.64066)
		(size 0.508)
		(drill 0.254)
		(layers "F.Cu" "B.Cu")
		(net "GND")
	)
	(via
		(at 289.250882 -284.866588)
		(size 0.4572)
		(drill 0.2032)
		(layers "F.Cu" "B.Cu")
		(net "GND")
	)
	(via
		(at 334.899508 -48.050196)
		(size 0.4572)
		(drill 0.2032)
		(layers "F.Cu" "B.Cu")
		(net "GND")
	)
	(via
		(at 380.366016 -281.59202)
		(size 0.4572)
		(drill 0.2032)
		(layers "F.Cu" "B.Cu")
		(net "GND")
	)
	(via
		(at 58.675524 -207.658716)
		(size 0.4572)
		(drill 0.2032)
		(layers "F.Cu" "B.Cu")
		(net "GND")
	)
	(via
		(at 169.352214 -232.166668)
		(size 0.4572)
		(drill 0.2032)
		(layers "F.Cu" "B.Cu")
		(net "GND")
	)
	(via
		(at 7.035546 -268.71676)
		(size 0.4572)
		(drill 0.2032)
		(layers "F.Cu" "B.Cu")
		(net "GND")
	)
	(via
		(at 316.380622 -60.315348)
		(size 0.508)
		(drill 0.254)
		(layers "F.Cu" "B.Cu")
		(net "GND")
	)
	(via
		(at 214.615014 -294.216582)
		(size 0.4572)
		(drill 0.2032)
		(layers "F.Cu" "B.Cu")
		(net "GND")
	)
	(via
		(at 415.139124 -156.610304)
		(size 0.508)
		(drill 0.254)
		(layers "F.Cu" "B.Cu")
		(net "GND")
	)
	(via
		(at 131.376166 -226.017328)
		(size 0.4572)
		(drill 0.2032)
		(layers "F.Cu" "B.Cu")
		(net "GND")
	)
	(via
		(at 56.398414 -306.96662)
		(size 0.4572)
		(drill 0.2032)
		(layers "F.Cu" "B.Cu")
		(net "GND")
	)
	(via
		(at 201.737214 -194.766692)
		(size 0.4572)
		(drill 0.2032)
		(layers "F.Cu" "B.Cu")
		(net "GND")
	)
	(via
		(at 132.850382 -335.129124)
		(size 0.508)
		(drill 0.254)
		(layers "F.Cu" "B.Cu")
		(net "GND")
	)
	(via
		(at 18.679414 -278.916638)
		(size 0.4572)
		(drill 0.2032)
		(layers "F.Cu" "B.Cu")
		(net "GND")
	)
	(via
		(at 157.708346 -276.366732)
		(size 0.4572)
		(drill 0.2032)
		(layers "F.Cu" "B.Cu")
		(net "GND")
	)
	(via
		(at 139.346686 -8.255)
		(size 0.508)
		(drill 0.254)
		(layers "F.Cu" "B.Cu")
		(net "GND")
	)
	(via
		(at 197.637146 -260.21665)
		(size 0.4572)
		(drill 0.2032)
		(layers "F.Cu" "B.Cu")
		(net "GND")
	)
	(via
		(at 60.035186 -404.51786)
		(size 0.4572)
		(drill 0.254)
		(layers "F.Cu" "B.Cu")
		(net "GND")
	)
	(via
		(at 332.697836 -410.664152)
		(size 0.4572)
		(drill 0.254)
		(layers "F.Cu" "B.Cu")
		(net "GND")
	)
	(via
		(at 96.243394 -259.616956)
		(size 0.4572)
		(drill 0.2032)
		(layers "F.Cu" "B.Cu")
		(net "GND")
	)
	(via
		(at 336.085434 -245.55069)
		(size 0.4572)
		(drill 0.2032)
		(layers "F.Cu" "B.Cu")
		(net "GND")
	)
	(via
		(at 107.991148 -273.453098)
		(size 0.4572)
		(drill 0.2032)
		(layers "F.Cu" "B.Cu")
		(net "GND")
	)
	(via
		(at 31.876746 -197.316598)
		(size 0.4572)
		(drill 0.2032)
		(layers "F.Cu" "B.Cu")
		(net "GND")
	)
	(via
		(at 57.684924 -177.987452)
		(size 0.508)
		(drill 0.254)
		(layers "F.Cu" "B.Cu")
		(net "GND")
	)
	(via
		(at 335.761076 -409.396184)
		(size 0.4572)
		(drill 0.254)
		(layers "F.Cu" "B.Cu")
		(net "GND")
	)
	(via
		(at 430.489614 -248.31675)
		(size 0.4572)
		(drill 0.2032)
		(layers "F.Cu" "B.Cu")
		(net "GND")
	)
	(via
		(at 56.398414 -216.866724)
		(size 0.4572)
		(drill 0.2032)
		(layers "F.Cu" "B.Cu")
		(net "GND")
	)
	(via
		(at 92.954348 -273.453098)
		(size 0.4572)
		(drill 0.2032)
		(layers "F.Cu" "B.Cu")
		(net "GND")
	)
	(via
		(at 382.135634 -222.761556)
		(size 0.4572)
		(drill 0.2032)
		(layers "F.Cu" "B.Cu")
		(net "GND")
	)
	(via
		(at 51.064414 -312.91657)
		(size 0.4572)
		(drill 0.2032)
		(layers "F.Cu" "B.Cu")
		(net "GND")
	)
	(via
		(at 352.406204 -331.776832)
		(size 0.49022)
		(drill 0.254)
		(layers "F.Cu" "B.Cu")
		(net "GND")
	)
	(via
		(at 442.133482 -280.61666)
		(size 0.4572)
		(drill 0.2032)
		(layers "F.Cu" "B.Cu")
		(net "GND")
	)
	(via
		(at 304.338482 -306.96662)
		(size 0.4572)
		(drill 0.2032)
		(layers "F.Cu" "B.Cu")
		(net "GND")
	)
	(via
		(at 40.063674 -355.531928)
		(size 0.49022)
		(drill 0.254)
		(layers "F.Cu" "B.Cu")
		(net "GND")
	)
	(via
		(at 13.345414 -200.716642)
		(size 0.4572)
		(drill 0.2032)
		(layers "F.Cu" "B.Cu")
		(net "GND")
	)
	(via
		(at 259.98932 -422.3258)
		(size 0.508)
		(drill 0.254)
		(layers "F.Cu" "B.Cu")
		(net "GND")
	)
	(via
		(at 96.713548 -281.59202)
		(size 0.4572)
		(drill 0.2032)
		(layers "F.Cu" "B.Cu")
		(net "GND")
	)
	(via
		(at 328.913998 -189.72911)
		(size 0.508)
		(drill 0.254)
		(layers "F.Cu" "B.Cu")
		(net "GND")
	)
	(via
		(at 50.561494 -351.608644)
		(size 0.49022)
		(drill 0.254)
		(layers "F.Cu" "B.Cu")
		(net "GND")
	)
	(via
		(at 296.794682 -258.516628)
		(size 0.4572)
		(drill 0.2032)
		(layers "F.Cu" "B.Cu")
		(net "GND")
	)
	(via
		(at 324.863968 -400.858228)
		(size 0.4064)
		(drill 0.2032)
		(layers "F.Cu" "B.Cu")
		(net "GND")
	)
	(via
		(at 84.08289 -409.396184)
		(size 0.4572)
		(drill 0.254)
		(layers "F.Cu" "B.Cu")
		(net "GND")
	)
	(via
		(at 438.033414 -204.96657)
		(size 0.4572)
		(drill 0.2032)
		(layers "F.Cu" "B.Cu")
		(net "GND")
	)
	(via
		(at 208.575656 -94.567248)
		(size 0.508)
		(drill 0.254)
		(layers "F.Cu" "B.Cu")
		(net "GND")
	)
	(via
		(at 125.847348 -263.686544)
		(size 0.4572)
		(drill 0.2032)
		(layers "F.Cu" "B.Cu")
		(net "GND")
	)
	(via
		(at 151.84628 -80.533748)
		(size 0.508)
		(drill 0.254)
		(layers "F.Cu" "B.Cu")
		(net "GND")
	)
	(via
		(at 39.420546 -258.516628)
		(size 0.4572)
		(drill 0.2032)
		(layers "F.Cu" "B.Cu")
		(net "GND")
	)
	(via
		(at 314.092082 -224.516696)
		(size 0.4572)
		(drill 0.2032)
		(layers "F.Cu" "B.Cu")
		(net "GND")
	)
	(via
		(at 132.210302 -403.249892)
		(size 0.4572)
		(drill 0.254)
		(layers "F.Cu" "B.Cu")
		(net "GND")
	)
	(via
		(at 54.508146 -231.316784)
		(size 0.4572)
		(drill 0.2032)
		(layers "F.Cu" "B.Cu")
		(net "GND")
	)
	(via
		(at 260.95198 -422.3258)
		(size 0.508)
		(drill 0.254)
		(layers "F.Cu" "B.Cu")
		(net "GND")
	)
	(via
		(at 430.489614 -197.316598)
		(size 0.4572)
		(drill 0.2032)
		(layers "F.Cu" "B.Cu")
		(net "GND")
	)
	(via
		(at 376.606816 -281.59202)
		(size 0.4572)
		(drill 0.2032)
		(layers "F.Cu" "B.Cu")
		(net "GND")
	)
	(via
		(at 41.310814 -284.866588)
		(size 0.4572)
		(drill 0.2032)
		(layers "F.Cu" "B.Cu")
		(net "GND")
	)
	(via
		(at 443.367414 -309.51678)
		(size 0.4572)
		(drill 0.2032)
		(layers "F.Cu" "B.Cu")
		(net "GND")
	)
	(via
		(at 88.250014 -435.0512)
		(size 0.4572)
		(drill 0.2032)
		(layers "F.Cu" "B.Cu")
		(net "GND")
	)
	(via
		(at 172.795946 -236.416596)
		(size 0.4572)
		(drill 0.2032)
		(layers "F.Cu" "B.Cu")
		(net "GND")
	)
	(via
		(at 85.325712 -227.64496)
		(size 0.4572)
		(drill 0.2032)
		(layers "F.Cu" "B.Cu")
		(net "GND")
	)
	(via
		(at 292.694614 -317.166752)
		(size 0.4572)
		(drill 0.2032)
		(layers "F.Cu" "B.Cu")
		(net "GND")
	)
	(via
		(at 407.858214 -290.816792)
		(size 0.4572)
		(drill 0.2032)
		(layers "F.Cu" "B.Cu")
		(net "GND")
	)
	(via
		(at 257.185414 -223.666558)
		(size 0.4572)
		(drill 0.2032)
		(layers "F.Cu" "B.Cu")
		(net "GND")
	)
	(via
		(at 245.21668 -92.892626)
		(size 0.508)
		(drill 0.254)
		(layers "F.Cu" "B.Cu")
		(net "GND")
	)
	(via
		(at 266.619482 -289.966654)
		(size 0.4572)
		(drill 0.2032)
		(layers "F.Cu" "B.Cu")
		(net "GND")
	)
	(via
		(at 56.398414 -224.516696)
		(size 0.4572)
		(drill 0.2032)
		(layers "F.Cu" "B.Cu")
		(net "GND")
	)
	(via
		(at 175.005746 -229.616762)
		(size 0.4572)
		(drill 0.2032)
		(layers "F.Cu" "B.Cu")
		(net "GND")
	)
	(via
		(at 82.824066 -407.638504)
		(size 0.4572)
		(drill 0.254)
		(layers "F.Cu" "B.Cu")
		(net "GND")
	)
	(via
		(at 453.196452 -38.288976)
		(size 0.508)
		(drill 0.254)
		(layers "F.Cu" "B.Cu")
		(net "GND")
	)
	(via
		(at 140.349986 -433.747164)
		(size 0.4572)
		(drill 0.2032)
		(layers "F.Cu" "B.Cu")
		(net "GND")
	)
	(via
		(at 291.460682 -282.316682)
		(size 0.4572)
		(drill 0.2032)
		(layers "F.Cu" "B.Cu")
		(net "GND")
	)
	(via
		(at 66.152014 -230.466646)
		(size 0.4572)
		(drill 0.2032)
		(layers "F.Cu" "B.Cu")
		(net "GND")
	)
	(via
		(at 335.138268 -52.679346)
		(size 0.4572)
		(drill 0.2032)
		(layers "F.Cu" "B.Cu")
		(net "GND")
	)
	(via
		(at 423.199814 -292.516814)
		(size 0.4572)
		(drill 0.2032)
		(layers "F.Cu" "B.Cu")
		(net "GND")
	)
	(via
		(at 464.764882 -224.516696)
		(size 0.4572)
		(drill 0.2032)
		(layers "F.Cu" "B.Cu")
		(net "GND")
	)
	(via
		(at 104.701594 -269.38351)
		(size 0.4572)
		(drill 0.2032)
		(layers "F.Cu" "B.Cu")
		(net "GND")
	)
	(via
		(at 462.555082 -249.166634)
		(size 0.4572)
		(drill 0.2032)
		(layers "F.Cu" "B.Cu")
		(net "GND")
	)
	(via
		(at 294.904414 -221.96679)
		(size 0.4572)
		(drill 0.2032)
		(layers "F.Cu" "B.Cu")
		(net "GND")
	)
	(via
		(at 169.062908 -291.666676)
		(size 0.4572)
		(drill 0.2032)
		(layers "F.Cu" "B.Cu")
		(net "GND")
	)
	(via
		(at 96.133412 -238.225584)
		(size 0.4572)
		(drill 0.2032)
		(layers "F.Cu" "B.Cu")
		(net "GND")
	)
	(via
		(at 338.463128 -410.030168)
		(size 0.4064)
		(drill 0.2032)
		(layers "F.Cu" "B.Cu")
		(net "GND")
	)
	(via
		(at 388.607808 -339.624416)
		(size 0.508)
		(drill 0.254)
		(layers "F.Cu" "B.Cu")
		(net "GND")
	)
	(via
		(at 67.250056 -431.451258)
		(size 0.4572)
		(drill 0.2032)
		(layers "F.Cu" "B.Cu")
		(net "GND")
	)
	(via
		(at 405.419814 -272.116804)
		(size 0.4572)
		(drill 0.2032)
		(layers "F.Cu" "B.Cu")
		(net "GND")
	)
	(via
		(at 91.652598 -407.00452)
		(size 0.4064)
		(drill 0.2032)
		(layers "F.Cu" "B.Cu")
		(net "GND")
	)
	(via
		(at 57.192418 -170.689524)
		(size 0.508)
		(drill 0.254)
		(layers "F.Cu" "B.Cu")
		(net "GND")
	)
	(via
		(at 455.749152 -323.429376)
		(size 0.4572)
		(drill 0.2032)
		(layers "F.Cu" "B.Cu")
		(net "GND")
	)
	(via
		(at 63.942214 -230.466646)
		(size 0.4572)
		(drill 0.2032)
		(layers "F.Cu" "B.Cu")
		(net "GND")
	)
	(via
		(at 296.794682 -198.166736)
		(size 0.4572)
		(drill 0.2032)
		(layers "F.Cu" "B.Cu")
		(net "GND")
	)
	(via
		(at 13.345414 -295.916604)
		(size 0.4572)
		(drill 0.2032)
		(layers "F.Cu" "B.Cu")
		(net "GND")
	)
	(via
		(at 13.345414 -308.666642)
		(size 0.4572)
		(drill 0.2032)
		(layers "F.Cu" "B.Cu")
		(net "GND")
	)
	(via
		(at 35.976814 -294.216582)
		(size 0.4572)
		(drill 0.2032)
		(layers "F.Cu" "B.Cu")
		(net "GND")
	)
	(via
		(at 342.773762 -281.59202)
		(size 0.4572)
		(drill 0.2032)
		(layers "F.Cu" "B.Cu")
		(net "GND")
	)
	(via
		(at 438.033414 -229.616762)
		(size 0.4572)
		(drill 0.2032)
		(layers "F.Cu" "B.Cu")
		(net "GND")
	)
	(via
		(at 370.51488 -41.112948)
		(size 0.508)
		(drill 0.254)
		(layers "F.Cu" "B.Cu")
		(net "GND")
	)
	(via
		(at 343.243662 -272.639282)
		(size 0.4572)
		(drill 0.2032)
		(layers "F.Cu" "B.Cu")
		(net "GND")
	)
	(via
		(at 134.426706 -25.399238)
		(size 0.508)
		(drill 0.254)
		(layers "F.Cu" "B.Cu")
		(net "GND")
	)
	(via
		(at 85.887306 -410.664152)
		(size 0.4572)
		(drill 0.254)
		(layers "F.Cu" "B.Cu")
		(net "GND")
	)
	(via
		(at 87.675466 -228.45903)
		(size 0.4572)
		(drill 0.2032)
		(layers "F.Cu" "B.Cu")
		(net "GND")
	)
	(via
		(at 383.185416 -270.19758)
		(size 0.4572)
		(drill 0.2032)
		(layers "F.Cu" "B.Cu")
		(net "GND")
	)
	(via
		(at 209.281014 -261.066788)
		(size 0.4572)
		(drill 0.2032)
		(layers "F.Cu" "B.Cu")
		(net "GND")
	)
	(via
		(at 124.640594 -403.883876)
		(size 0.4064)
		(drill 0.2032)
		(layers "F.Cu" "B.Cu")
		(net "GND")
	)
	(via
		(at 306.548282 -211.766658)
		(size 0.4572)
		(drill 0.2032)
		(layers "F.Cu" "B.Cu")
		(net "GND")
	)
	(via
		(at 268.829282 -245.76659)
		(size 0.4572)
		(drill 0.2032)
		(layers "F.Cu" "B.Cu")
		(net "GND")
	)
	(via
		(at 20.889214 -264.466578)
		(size 0.4572)
		(drill 0.2032)
		(layers "F.Cu" "B.Cu")
		(net "GND")
	)
	(via
		(at 180.339746 -313.766708)
		(size 0.4572)
		(drill 0.2032)
		(layers "F.Cu" "B.Cu")
		(net "GND")
	)
	(via
		(at 261.86892 -152.075388)
		(size 0.508)
		(drill 0.254)
		(layers "F.Cu" "B.Cu")
		(net "GND")
	)
	(via
		(at 51.064414 -272.966688)
		(size 0.4572)
		(drill 0.2032)
		(layers "F.Cu" "B.Cu")
		(net "GND")
	)
	(via
		(at 424.836082 -308.666642)
		(size 0.4572)
		(drill 0.2032)
		(layers "F.Cu" "B.Cu")
		(net "GND")
	)
	(via
		(at 160.142174 -217.716608)
		(size 0.4572)
		(drill 0.2032)
		(layers "F.Cu" "B.Cu")
		(net "GND")
	)
	(via
		(at 120.098566 -219.506038)
		(size 0.4572)
		(drill 0.2032)
		(layers "F.Cu" "B.Cu")
		(net "GND")
	)
	(via
		(at 427.045882 -305.266598)
		(size 0.4572)
		(drill 0.2032)
		(layers "F.Cu" "B.Cu")
		(net "GND")
	)
	(via
		(at 136.545066 -228.45903)
		(size 0.4318)
		(drill 0.2032)
		(layers "F.Cu" "B.Cu")
		(net "GND")
	)
	(via
		(at 207.071214 -210.066636)
		(size 0.4572)
		(drill 0.2032)
		(layers "F.Cu" "B.Cu")
		(net "GND")
	)
	(via
		(at 467.535514 -358.00538)
		(size 0.508)
		(drill 0.254)
		(layers "F.Cu" "B.Cu")
		(net "GND")
	)
	(via
		(at 368.148616 -281.59202)
		(size 0.4572)
		(drill 0.2032)
		(layers "F.Cu" "B.Cu")
		(net "GND")
	)
	(via
		(at 184.439814 -301.01667)
		(size 0.4572)
		(drill 0.2032)
		(layers "F.Cu" "B.Cu")
		(net "GND")
	)
	(via
		(at 180.339746 -287.416748)
		(size 0.4572)
		(drill 0.2032)
		(layers "F.Cu" "B.Cu")
		(net "GND")
	)
	(via
		(at 102.5398 -102.215188)
		(size 0.508)
		(drill 0.254)
		(layers "F.Cu" "B.Cu")
		(net "GND")
	)
	(via
		(at 59.842146 -223.666558)
		(size 0.4572)
		(drill 0.2032)
		(layers "F.Cu" "B.Cu")
		(net "GND")
	)
	(via
		(at 61.250068 -434.899562)
		(size 0.4572)
		(drill 0.2032)
		(layers "F.Cu" "B.Cu")
		(net "GND")
	)
	(via
		(at 254.975614 -246.616728)
		(size 0.4572)
		(drill 0.2032)
		(layers "F.Cu" "B.Cu")
		(net "GND")
	)
	(via
		(at 184.439814 -198.166736)
		(size 0.4572)
		(drill 0.2032)
		(layers "F.Cu" "B.Cu")
		(net "GND")
	)
	(via
		(at 118.99646 -86.505288)
		(size 0.508)
		(drill 0.254)
		(layers "F.Cu" "B.Cu")
		(net "GND")
	)
	(via
		(at 9.245346 -203.266802)
		(size 0.4572)
		(drill 0.2032)
		(layers "F.Cu" "B.Cu")
		(net "GND")
	)
	(via
		(at 130.076448 -277.522432)
		(size 0.4572)
		(drill 0.2032)
		(layers "F.Cu" "B.Cu")
		(net "GND")
	)
	(via
		(at 180.339746 -229.616762)
		(size 0.4572)
		(drill 0.2032)
		(layers "F.Cu" "B.Cu")
		(net "GND")
	)
	(via
		(at 46.553882 -350.567498)
		(size 0.508)
		(drill 0.254)
		(layers "F.Cu" "B.Cu")
		(net "GND")
	)
	(via
		(at 407.190194 -5.585714)
		(size 0.508)
		(drill 0.254)
		(layers "F.Cu" "B.Cu")
		(net "GND")
	)
	(via
		(at 420.736014 -197.316598)
		(size 0.4572)
		(drill 0.2032)
		(layers "F.Cu" "B.Cu")
		(net "GND")
	)
	(via
		(at 340.894162 -289.807142)
		(size 0.4572)
		(drill 0.2032)
		(layers "F.Cu" "B.Cu")
		(net "GND")
	)
	(via
		(at 412.989014 -273.816572)
		(size 0.4572)
		(drill 0.2032)
		(layers "F.Cu" "B.Cu")
		(net "GND")
	)
	(via
		(at 104.281986 -335.704434)
		(size 0.49022)
		(drill 0.254)
		(layers "F.Cu" "B.Cu")
		(net "GND")
	)
	(via
		(at 345.593162 -262.058658)
		(size 0.4572)
		(drill 0.2032)
		(layers "F.Cu" "B.Cu")
		(net "GND")
	)
	(via
		(at 413.192214 -203.266802)
		(size 0.4572)
		(drill 0.2032)
		(layers "F.Cu" "B.Cu")
		(net "GND")
	)
	(via
		(at 395.731238 -404.51786)
		(size 0.4572)
		(drill 0.254)
		(layers "F.Cu" "B.Cu")
		(net "GND")
	)
	(via
		(at 83.54441 -337.643216)
		(size 0.508)
		(drill 0.254)
		(layers "F.Cu" "B.Cu")
		(net "GND")
	)
	(via
		(at 127.616966 -232.528364)
		(size 0.4572)
		(drill 0.2032)
		(layers "F.Cu" "B.Cu")
		(net "GND")
	)
	(via
		(at 105.641394 -267.755878)
		(size 0.4572)
		(drill 0.2032)
		(layers "F.Cu" "B.Cu")
		(net "GND")
	)
	(via
		(at 440.278012 -34.266378)
		(size 0.508)
		(drill 0.254)
		(layers "F.Cu" "B.Cu")
		(net "GND")
	)
	(via
		(at 328.288396 -400.224244)
		(size 0.4572)
		(drill 0.254)
		(layers "F.Cu" "B.Cu")
		(net "GND")
	)
	(via
		(at 430.587658 -183.47055)
		(size 0.508)
		(drill 0.254)
		(layers "F.Cu" "B.Cu")
		(net "GND")
	)
	(via
		(at 190.093346 -250.016772)
		(size 0.4572)
		(drill 0.2032)
		(layers "F.Cu" "B.Cu")
		(net "GND")
	)
	(via
		(at 443.367414 -287.416748)
		(size 0.4572)
		(drill 0.2032)
		(layers "F.Cu" "B.Cu")
		(net "GND")
	)
	(via
		(at 445.577214 -234.716574)
		(size 0.4572)
		(drill 0.2032)
		(layers "F.Cu" "B.Cu")
		(net "GND")
	)
	(via
		(at 351.592134 -226.831144)
		(size 0.4572)
		(drill 0.2032)
		(layers "F.Cu" "B.Cu")
		(net "GND")
	)
	(via
		(at 304.446686 -12.544552)
		(size 0.508)
		(drill 0.254)
		(layers "F.Cu" "B.Cu")
		(net "GND")
	)
	(via
		(at 195.398136 -26.38933)
		(size 0.508)
		(drill 0.254)
		(layers "F.Cu" "B.Cu")
		(net "GND")
	)
	(via
		(at 142.746222 -409.396184)
		(size 0.4572)
		(drill 0.254)
		(layers "F.Cu" "B.Cu")
		(net "GND")
	)
	(via
		(at 35.976814 -314.616592)
		(size 0.4572)
		(drill 0.2032)
		(layers "F.Cu" "B.Cu")
		(net "GND")
	)
	(via
		(at 266.619482 -249.166634)
		(size 0.4572)
		(drill 0.2032)
		(layers "F.Cu" "B.Cu")
		(net "GND")
	)
	(via
		(at 428.279814 -206.666592)
		(size 0.4572)
		(drill 0.2032)
		(layers "F.Cu" "B.Cu")
		(net "GND")
	)
	(via
		(at 383.655062 -274.266914)
		(size 0.4572)
		(drill 0.2032)
		(layers "F.Cu" "B.Cu")
		(net "GND")
	)
	(via
		(at 412.355792 -359.366312)
		(size 0.508)
		(drill 0.254)
		(layers "F.Cu" "B.Cu")
		(net "GND")
	)
	(via
		(at 438.033414 -301.866808)
		(size 0.4572)
		(drill 0.2032)
		(layers "F.Cu" "B.Cu")
		(net "GND")
	)
	(via
		(at 340.784434 -247.178322)
		(size 0.4572)
		(drill 0.2032)
		(layers "F.Cu" "B.Cu")
		(net "GND")
	)
	(via
		(at 158.62808 -39.273988)
		(size 0.508)
		(drill 0.254)
		(layers "F.Cu" "B.Cu")
		(net "GND")
	)
	(via
		(at 212.724746 -248.31675)
		(size 0.4572)
		(drill 0.2032)
		(layers "F.Cu" "B.Cu")
		(net "GND")
	)
	(via
		(at 128.947926 -335.187036)
		(size 0.49022)
		(drill 0.254)
		(layers "F.Cu" "B.Cu")
		(net "GND")
	)
	(via
		(at 202.971146 -199.01662)
		(size 0.4572)
		(drill 0.2032)
		(layers "F.Cu" "B.Cu")
		(net "GND")
	)
	(via
		(at 401.349972 -430.147222)
		(size 0.4572)
		(drill 0.2032)
		(layers "F.Cu" "B.Cu")
		(net "GND")
	)
	(via
		(at 445.57823 -68.509896)
		(size 0.508)
		(drill 0.254)
		(layers "F.Cu" "B.Cu")
		(net "GND")
	)
	(via
		(at 54.78145 -350.915732)
		(size 0.508)
		(drill 0.254)
		(layers "F.Cu" "B.Cu")
		(net "GND")
	)
	(via
		(at 432.74488 -129.377948)
		(size 0.508)
		(drill 0.254)
		(layers "F.Cu" "B.Cu")
		(net "GND")
	)
	(via
		(at 281.707082 -210.066636)
		(size 0.4572)
		(drill 0.2032)
		(layers "F.Cu" "B.Cu")
		(net "GND")
	)
	(via
		(at 53.002688 -4.328668)
		(size 0.508)
		(drill 0.254)
		(layers "F.Cu" "B.Cu")
		(net "GND")
	)
	(via
		(at 125.625606 -407.638504)
		(size 0.4572)
		(drill 0.254)
		(layers "F.Cu" "B.Cu")
		(net "GND")
	)
	(via
		(at 93.784166 -226.017328)
		(size 0.4572)
		(drill 0.2032)
		(layers "F.Cu" "B.Cu")
		(net "GND")
	)
	(via
		(at 442.2648 -49.240948)
		(size 0.508)
		(drill 0.254)
		(layers "F.Cu" "B.Cu")
		(net "GND")
	)
	(via
		(at 201.737214 -226.216718)
		(size 0.4572)
		(drill 0.2032)
		(layers "F.Cu" "B.Cu")
		(net "GND")
	)
	(via
		(at 101.882194 -254.733552)
		(size 0.4572)
		(drill 0.2032)
		(layers "F.Cu" "B.Cu")
		(net "GND")
	)
	(via
		(at 63.942214 -222.816674)
		(size 0.4572)
		(drill 0.2032)
		(layers "F.Cu" "B.Cu")
		(net "GND")
	)
	(via
		(at 109.657388 -295.03878)
		(size 0.508)
		(drill 0.254)
		(layers "F.Cu" "B.Cu")
		(net "GND")
	)
	(via
		(at 380.366016 -268.569694)
		(size 0.4572)
		(drill 0.2032)
		(layers "F.Cu" "B.Cu")
		(net "GND")
	)
	(via
		(at 221.540832 -439.905394)
		(size 0.508)
		(drill 0.254)
		(layers "F.Cu" "B.Cu")
		(net "GND")
	)
	(via
		(at 209.422492 -36.880292)
		(size 0.508)
		(drill 0.254)
		(layers "F.Cu" "B.Cu")
		(net "GND")
	)
	(via
		(at 283.549852 -434.69052)
		(size 0.508)
		(drill 0.254)
		(layers "F.Cu" "B.Cu")
		(net "GND")
	)
	(via
		(at 414.85947 -171.513754)
		(size 0.49022)
		(drill 0.254)
		(layers "F.Cu" "B.Cu")
		(net "GND")
	)
	(via
		(at 7.035546 -296.766742)
		(size 0.4572)
		(drill 0.2032)
		(layers "F.Cu" "B.Cu")
		(net "GND")
	)
	(via
		(at 63.942214 -202.416664)
		(size 0.4572)
		(drill 0.2032)
		(layers "F.Cu" "B.Cu")
		(net "GND")
	)
	(via
		(at 91.904312 -227.64496)
		(size 0.4572)
		(drill 0.2032)
		(layers "F.Cu" "B.Cu")
		(net "GND")
	)
	(via
		(at 59.654186 -238.966756)
		(size 0.4572)
		(drill 0.2032)
		(layers "F.Cu" "B.Cu")
		(net "GND")
	)
	(via
		(at 262.519414 -216.016586)
		(size 0.4572)
		(drill 0.2032)
		(layers "F.Cu" "B.Cu")
		(net "GND")
	)
	(via
		(at 374.038368 -332.47203)
		(size 0.508)
		(drill 0.254)
		(layers "F.Cu" "B.Cu")
		(net "GND")
	)
	(via
		(at 84.250022 -429.147224)
		(size 0.4572)
		(drill 0.2032)
		(layers "F.Cu" "B.Cu")
		(net "GND")
	)
	(via
		(at 407.446988 -12.37488)
		(size 0.508)
		(drill 0.254)
		(layers "F.Cu" "B.Cu")
		(net "GND")
	)
	(via
		(at 91.92641 -400.200368)
		(size 0.4572)
		(drill 0.254)
		(layers "F.Cu" "B.Cu")
		(net "GND")
	)
	(via
		(at 155.349956 -427.851316)
		(size 0.4572)
		(drill 0.2032)
		(layers "F.Cu" "B.Cu")
		(net "GND")
	)
	(via
		(at 279.816814 -246.616728)
		(size 0.4572)
		(drill 0.2032)
		(layers "F.Cu" "B.Cu")
		(net "GND")
	)
	(via
		(at 96.243394 -274.266914)
		(size 0.4572)
		(drill 0.2032)
		(layers "F.Cu" "B.Cu")
		(net "GND")
	)
	(via
		(at 97.31756 -30.434788)
		(size 0.508)
		(drill 0.254)
		(layers "F.Cu" "B.Cu")
		(net "GND")
	)
	(via
		(at 94.201996 -339.312504)
		(size 0.508)
		(drill 0.254)
		(layers "F.Cu" "B.Cu")
		(net "GND")
	)
	(via
		(at 347.92666 -403.249892)
		(size 0.4572)
		(drill 0.254)
		(layers "F.Cu" "B.Cu")
		(net "GND")
	)
	(via
		(at 46.964346 -208.366614)
		(size 0.4572)
		(drill 0.2032)
		(layers "F.Cu" "B.Cu")
		(net "GND")
	)
	(via
		(at 405.549862 -295.06672)
		(size 0.4572)
		(drill 0.2032)
		(layers "F.Cu" "B.Cu")
		(net "GND")
	)
	(via
		(at 23.760176 -383.565146)
		(size 0.508)
		(drill 0.254)
		(layers "F.Cu" "B.Cu")
		(net "GND")
	)
	(via
		(at 334.785462 -285.661354)
		(size 0.4572)
		(drill 0.2032)
		(layers "F.Cu" "B.Cu")
		(net "GND")
	)
	(via
		(at 334.414876 -400.224244)
		(size 0.4572)
		(drill 0.254)
		(layers "F.Cu" "B.Cu")
		(net "GND")
	)
	(via
		(at 335.14538 -227.64496)
		(size 0.4572)
		(drill 0.2032)
		(layers "F.Cu" "B.Cu")
		(net "GND")
	)
	(via
		(at 429.053752 -323.429376)
		(size 0.4572)
		(drill 0.2032)
		(layers "F.Cu" "B.Cu")
		(net "GND")
	)
	(via
		(at 87.315294 -288.103056)
		(size 0.4572)
		(drill 0.2032)
		(layers "F.Cu" "B.Cu")
		(net "GND")
	)
	(via
		(at 29.666946 -317.166752)
		(size 0.4572)
		(drill 0.2032)
		(layers "F.Cu" "B.Cu")
		(net "GND")
	)
	(via
		(at 59.842146 -307.816758)
		(size 0.4572)
		(drill 0.2032)
		(layers "F.Cu" "B.Cu")
		(net "GND")
	)
	(via
		(at 71.250048 -438.651396)
		(size 0.4572)
		(drill 0.2032)
		(layers "F.Cu" "B.Cu")
		(net "GND")
	)
	(via
		(at 331.351636 -403.249892)
		(size 0.4572)
		(drill 0.254)
		(layers "F.Cu" "B.Cu")
		(net "GND")
	)
	(via
		(at 438.033414 -210.916774)
		(size 0.4572)
		(drill 0.2032)
		(layers "F.Cu" "B.Cu")
		(net "GND")
	)
	(via
		(at 172.795946 -204.96657)
		(size 0.4572)
		(drill 0.2032)
		(layers "F.Cu" "B.Cu")
		(net "GND")
	)
	(via
		(at 24.332946 -315.46673)
		(size 0.4572)
		(drill 0.2032)
		(layers "F.Cu" "B.Cu")
		(net "GND")
	)
	(via
		(at 362.86948 -215.436704)
		(size 0.4572)
		(drill 0.2032)
		(layers "F.Cu" "B.Cu")
		(net "GND")
	)
	(via
		(at 157.489144 -313.766708)
		(size 0.4572)
		(drill 0.2032)
		(layers "F.Cu" "B.Cu")
		(net "GND")
	)
	(via
		(at 98.592894 -275.08073)
		(size 0.4572)
		(drill 0.2032)
		(layers "F.Cu" "B.Cu")
		(net "GND")
	)
	(via
		(at 345.566492 -331.776832)
		(size 0.49022)
		(drill 0.254)
		(layers "F.Cu" "B.Cu")
		(net "GND")
	)
	(via
		(at 41.310814 -194.766692)
		(size 0.4572)
		(drill 0.2032)
		(layers "F.Cu" "B.Cu")
		(net "GND")
	)
	(via
		(at 9.245346 -240.666778)
		(size 0.4572)
		(drill 0.2032)
		(layers "F.Cu" "B.Cu")
		(net "GND")
	)
	(via
		(at 9.245346 -276.366732)
		(size 0.4572)
		(drill 0.2032)
		(layers "F.Cu" "B.Cu")
		(net "GND")
	)
	(via
		(at 216.824814 -232.166668)
		(size 0.4572)
		(drill 0.2032)
		(layers "F.Cu" "B.Cu")
		(net "GND")
	)
	(via
		(at 202.971146 -276.366732)
		(size 0.4572)
		(drill 0.2032)
		(layers "F.Cu" "B.Cu")
		(net "GND")
	)
	(via
		(at 433.166774 -12.37488)
		(size 0.508)
		(drill 0.254)
		(layers "F.Cu" "B.Cu")
		(net "GND")
	)
	(via
		(at 304.338482 -194.766692)
		(size 0.4572)
		(drill 0.2032)
		(layers "F.Cu" "B.Cu")
		(net "GND")
	)
	(via
		(at 299.004482 -295.916604)
		(size 0.4572)
		(drill 0.2032)
		(layers "F.Cu" "B.Cu")
		(net "GND")
	)
	(via
		(at 216.824814 -202.416664)
		(size 0.4572)
		(drill 0.2032)
		(layers "F.Cu" "B.Cu")
		(net "GND")
	)
	(via
		(at 287.433766 -360.83621)
		(size 0.49022)
		(drill 0.254)
		(layers "F.Cu" "B.Cu")
		(net "GND")
	)
	(via
		(at 341.172546 -82.413094)
		(size 0.508)
		(drill 0.254)
		(layers "F.Cu" "B.Cu")
		(net "GND")
	)
	(via
		(at 22.147022 -7.215124)
		(size 0.508)
		(drill 0.254)
		(layers "F.Cu" "B.Cu")
		(net "GND")
	)
	(via
		(at 234.79252 -388.01294)
		(size 0.508)
		(drill 0.254)
		(layers "F.Cu" "B.Cu")
		(net "GND")
	)
	(via
		(at 411.349952 -436.347362)
		(size 0.4572)
		(drill 0.2032)
		(layers "F.Cu" "B.Cu")
		(net "GND")
	)
	(via
		(at 325.128128 -410.030168)
		(size 0.4064)
		(drill 0.2032)
		(layers "F.Cu" "B.Cu")
		(net "GND")
	)
	(via
		(at 64.262 -7.203948)
		(size 0.508)
		(drill 0.254)
		(layers "F.Cu" "B.Cu")
		(net "GND")
	)
	(via
		(at 199.527414 -200.716642)
		(size 0.4572)
		(drill 0.2032)
		(layers "F.Cu" "B.Cu")
		(net "GND")
	)
	(via
		(at 339.014816 -263.686544)
		(size 0.4572)
		(drill 0.2032)
		(layers "F.Cu" "B.Cu")
		(net "GND")
	)
	(via
		(at 439.32348 -14.544548)
		(size 0.508)
		(drill 0.254)
		(layers "F.Cu" "B.Cu")
		(net "GND")
	)
	(via
		(at 371.327934 -223.575626)
		(size 0.4572)
		(drill 0.2032)
		(layers "F.Cu" "B.Cu")
		(net "GND")
	)
	(via
		(at 31.876746 -225.36658)
		(size 0.4572)
		(drill 0.2032)
		(layers "F.Cu" "B.Cu")
		(net "GND")
	)
	(via
		(at 331.880718 -46.100746)
		(size 0.4572)
		(drill 0.2032)
		(layers "F.Cu" "B.Cu")
		(net "GND")
	)
	(via
		(at 67.397122 -62.09284)
		(size 0.508)
		(drill 0.254)
		(layers "F.Cu" "B.Cu")
		(net "GND")
	)
	(via
		(at 365.3282 -405.9936)
		(size 0.508)
		(drill 0.254)
		(layers "F.Cu" "B.Cu")
		(net "GND")
	)
	(via
		(at 216.824814 -239.81664)
		(size 0.4572)
		(drill 0.2032)
		(layers "F.Cu" "B.Cu")
		(net "GND")
	)
	(via
		(at 58.608214 -249.166634)
		(size 0.4572)
		(drill 0.2032)
		(layers "F.Cu" "B.Cu")
		(net "GND")
	)
	(via
		(at 273.62658 -95.029274)
		(size 0.508)
		(drill 0.254)
		(layers "F.Cu" "B.Cu")
		(net "GND")
	)
	(via
		(at 216.824814 -271.266666)
		(size 0.4572)
		(drill 0.2032)
		(layers "F.Cu" "B.Cu")
		(net "GND")
	)
	(via
		(at 254.975614 -265.316716)
		(size 0.4572)
		(drill 0.2032)
		(layers "F.Cu" "B.Cu")
		(net "GND")
	)
	(via
		(at 164.018214 -211.766658)
		(size 0.4572)
		(drill 0.2032)
		(layers "F.Cu" "B.Cu")
		(net "GND")
	)
	(via
		(at 407.858214 -203.266802)
		(size 0.4572)
		(drill 0.2032)
		(layers "F.Cu" "B.Cu")
		(net "GND")
	)
	(via
		(at 171.765214 -275.516594)
		(size 0.4572)
		(drill 0.2032)
		(layers "F.Cu" "B.Cu")
		(net "GND")
	)
	(via
		(at 281.707082 -316.316614)
		(size 0.4572)
		(drill 0.2032)
		(layers "F.Cu" "B.Cu")
		(net "GND")
	)
	(via
		(at 295.077896 -359.513124)
		(size 0.508)
		(drill 0.254)
		(layers "F.Cu" "B.Cu")
		(net "GND")
	)
	(via
		(at 388.349998 -436.051198)
		(size 0.4572)
		(drill 0.2032)
		(layers "F.Cu" "B.Cu")
		(net "GND")
	)
	(via
		(at 411.52318 -175.707548)
		(size 0.508)
		(drill 0.254)
		(layers "F.Cu" "B.Cu")
		(net "GND")
	)
	(via
		(at 93.314266 -217.064336)
		(size 0.4572)
		(drill 0.2032)
		(layers "F.Cu" "B.Cu")
		(net "GND")
	)
	(via
		(at 20.889214 -282.316682)
		(size 0.4572)
		(drill 0.2032)
		(layers "F.Cu" "B.Cu")
		(net "GND")
	)
	(via
		(at 414.863534 -159.996378)
		(size 0.49022)
		(drill 0.254)
		(layers "F.Cu" "B.Cu")
		(net "GND")
	)
	(via
		(at 180.339746 -204.96657)
		(size 0.4572)
		(drill 0.2032)
		(layers "F.Cu" "B.Cu")
		(net "GND")
	)
	(via
		(at 22.147022 -9.424924)
		(size 0.508)
		(drill 0.254)
		(layers "F.Cu" "B.Cu")
		(net "GND")
	)
	(via
		(at 358.640634 -219.506038)
		(size 0.4572)
		(drill 0.2032)
		(layers "F.Cu" "B.Cu")
		(net "GND")
	)
	(via
		(at 210.514946 -251.716794)
		(size 0.4572)
		(drill 0.2032)
		(layers "F.Cu" "B.Cu")
		(net "GND")
	)
	(via
		(at 104.62514 -412.550356)
		(size 0.508)
		(drill 0.254)
		(layers "F.Cu" "B.Cu")
		(net "GND")
	)
	(via
		(at 411.958282 -198.166736)
		(size 0.4572)
		(drill 0.2032)
		(layers "F.Cu" "B.Cu")
		(net "GND")
	)
	(via
		(at 186.649614 -282.316682)
		(size 0.4572)
		(drill 0.2032)
		(layers "F.Cu" "B.Cu")
		(net "GND")
	)
	(via
		(at 259.075682 -261.066788)
		(size 0.4572)
		(drill 0.2032)
		(layers "F.Cu" "B.Cu")
		(net "GND")
	)
	(via
		(at 285.150814 -309.51678)
		(size 0.4572)
		(drill 0.2032)
		(layers "F.Cu" "B.Cu")
		(net "GND")
	)
	(via
		(at 384.015234 -214.546434)
		(size 0.4572)
		(drill 0.2032)
		(layers "F.Cu" "B.Cu")
		(net "GND")
	)
	(via
		(at 13.909548 -113.028222)
		(size 0.508)
		(drill 0.254)
		(layers "F.Cu" "B.Cu")
		(net "GND")
	)
	(via
		(at 105.78719 -331.776832)
		(size 0.49022)
		(drill 0.254)
		(layers "F.Cu" "B.Cu")
		(net "GND")
	)
	(via
		(at 431.609754 -134.494778)
		(size 0.508)
		(drill 0.254)
		(layers "F.Cu" "B.Cu")
		(net "GND")
	)
	(via
		(at 304.338482 -216.866724)
		(size 0.4572)
		(drill 0.2032)
		(layers "F.Cu" "B.Cu")
		(net "GND")
	)
	(via
		(at 156.619194 -407.00452)
		(size 0.4064)
		(drill 0.2032)
		(layers "F.Cu" "B.Cu")
		(net "GND")
	)
	(via
		(at 342.774016 -271.825212)
		(size 0.4572)
		(drill 0.2032)
		(layers "F.Cu" "B.Cu")
		(net "GND")
	)
	(via
		(at 18.679414 -210.066636)
		(size 0.4572)
		(drill 0.2032)
		(layers "F.Cu" "B.Cu")
		(net "GND")
	)
	(via
		(at 314.307982 -235.566712)
		(size 0.4572)
		(drill 0.2032)
		(layers "F.Cu" "B.Cu")
		(net "GND")
	)
	(via
		(at 415.286444 -362.649262)
		(size 0.49022)
		(drill 0.254)
		(layers "F.Cu" "B.Cu")
		(net "GND")
	)
	(via
		(at 412.12389 -235.591604)
		(size 0.4572)
		(drill 0.2032)
		(layers "F.Cu" "B.Cu")
		(net "GND")
	)
	(via
		(at 306.347622 -30.571948)
		(size 0.508)
		(drill 0.254)
		(layers "F.Cu" "B.Cu")
		(net "GND")
	)
	(via
		(at 415.402014 -296.766742)
		(size 0.4572)
		(drill 0.2032)
		(layers "F.Cu" "B.Cu")
		(net "GND")
	)
	(via
		(at 31.876746 -296.766742)
		(size 0.4572)
		(drill 0.2032)
		(layers "F.Cu" "B.Cu")
		(net "GND")
	)
	(via
		(at 462.555082 -247.466612)
		(size 0.4572)
		(drill 0.2032)
		(layers "F.Cu" "B.Cu")
		(net "GND")
	)
	(via
		(at 415.402014 -240.666778)
		(size 0.4572)
		(drill 0.2032)
		(layers "F.Cu" "B.Cu")
		(net "GND")
	)
	(via
		(at 307.782214 -270.416782)
		(size 0.4572)
		(drill 0.2032)
		(layers "F.Cu" "B.Cu")
		(net "GND")
	)
	(via
		(at 389.268208 -339.624416)
		(size 0.508)
		(drill 0.254)
		(layers "F.Cu" "B.Cu")
		(net "GND")
	)
	(via
		(at 87.14613 -410.664152)
		(size 0.4572)
		(drill 0.254)
		(layers "F.Cu" "B.Cu")
		(net "GND")
	)
	(via
		(at 231.700832 -439.905394)
		(size 0.508)
		(drill 0.254)
		(layers "F.Cu" "B.Cu")
		(net "GND")
	)
	(via
		(at 167.461946 -265.316716)
		(size 0.4572)
		(drill 0.2032)
		(layers "F.Cu" "B.Cu")
		(net "GND")
	)
	(via
		(at 85.905594 -254.733552)
		(size 0.4572)
		(drill 0.2032)
		(layers "F.Cu" "B.Cu")
		(net "GND")
	)
	(via
		(at 355.26218 -333.356458)
		(size 0.49022)
		(drill 0.254)
		(layers "F.Cu" "B.Cu")
		(net "GND")
	)
	(via
		(at 336.195162 -271.825212)
		(size 0.4572)
		(drill 0.2032)
		(layers "F.Cu" "B.Cu")
		(net "GND")
	)
	(via
		(at 430.489614 -276.366732)
		(size 0.4572)
		(drill 0.2032)
		(layers "F.Cu" "B.Cu")
		(net "GND")
	)
	(via
		(at 118.328948 -268.569694)
		(size 0.4572)
		(drill 0.2032)
		(layers "F.Cu" "B.Cu")
		(net "GND")
	)
	(via
		(at 345.15171 -51.59248)
		(size 0.4572)
		(drill 0.2032)
		(layers "F.Cu" "B.Cu")
		(net "GND")
	)
	(via
		(at 434.589682 -301.01667)
		(size 0.4572)
		(drill 0.2032)
		(layers "F.Cu" "B.Cu")
		(net "GND")
	)
	(via
		(at 160.121346 -272.116804)
		(size 0.4572)
		(drill 0.2032)
		(layers "F.Cu" "B.Cu")
		(net "GND")
	)
	(via
		(at 185.177684 -323.434456)
		(size 0.4572)
		(drill 0.2032)
		(layers "F.Cu" "B.Cu")
		(net "GND")
	)
	(via
		(at 37.210746 -204.96657)
		(size 0.4572)
		(drill 0.2032)
		(layers "F.Cu" "B.Cu")
		(net "GND")
	)
	(via
		(at 154.999182 -407.638504)
		(size 0.4572)
		(drill 0.254)
		(layers "F.Cu" "B.Cu")
		(net "GND")
	)
	(via
		(at 412.676086 -182.999126)
		(size 0.508)
		(drill 0.254)
		(layers "F.Cu" "B.Cu")
		(net "GND")
	)
	(via
		(at 307.782214 -290.816792)
		(size 0.4572)
		(drill 0.2032)
		(layers "F.Cu" "B.Cu")
		(net "GND")
	)
	(via
		(at 337.49488 -249.620024)
		(size 0.4572)
		(drill 0.2032)
		(layers "F.Cu" "B.Cu")
		(net "GND")
	)
	(via
		(at 368.066828 -331.776832)
		(size 0.49022)
		(drill 0.254)
		(layers "F.Cu" "B.Cu")
		(net "GND")
	)
	(via
		(at 180.339746 -301.866808)
		(size 0.4572)
		(drill 0.2032)
		(layers "F.Cu" "B.Cu")
		(net "GND")
	)
	(via
		(at 296.794682 -267.866622)
		(size 0.4572)
		(drill 0.2032)
		(layers "F.Cu" "B.Cu")
		(net "GND")
	)
	(via
		(at 28.433014 -314.616592)
		(size 0.4572)
		(drill 0.2032)
		(layers "F.Cu" "B.Cu")
		(net "GND")
	)
	(via
		(at 347.363034 -239.0394)
		(size 0.4572)
		(drill 0.2032)
		(layers "F.Cu" "B.Cu")
		(net "GND")
	)
	(via
		(at 105.018586 -32.781494)
		(size 0.508)
		(drill 0.254)
		(layers "F.Cu" "B.Cu")
		(net "GND")
	)
	(via
		(at 190.093346 -283.166566)
		(size 0.4572)
		(drill 0.2032)
		(layers "F.Cu" "B.Cu")
		(net "GND")
	)
	(via
		(at 90.25001 -430.147222)
		(size 0.4572)
		(drill 0.2032)
		(layers "F.Cu" "B.Cu")
		(net "GND")
	)
	(via
		(at 418.356796 -9.424924)
		(size 0.508)
		(drill 0.254)
		(layers "F.Cu" "B.Cu")
		(net "GND")
	)
	(via
		(at 186.649614 -250.866656)
		(size 0.4572)
		(drill 0.2032)
		(layers "F.Cu" "B.Cu")
		(net "GND")
	)
	(via
		(at 332.61046 -400.224244)
		(size 0.4572)
		(drill 0.254)
		(layers "F.Cu" "B.Cu")
		(net "GND")
	)
	(via
		(at 372.484142 -400.224244)
		(size 0.4572)
		(drill 0.254)
		(layers "F.Cu" "B.Cu")
		(net "GND")
	)
	(via
		(at 409.748482 -244.066568)
		(size 0.4572)
		(drill 0.2032)
		(layers "F.Cu" "B.Cu")
		(net "GND")
	)
	(via
		(at 169.653204 -392.942572)
		(size 0.508)
		(drill 0.254)
		(layers "F.Cu" "B.Cu")
		(net "GND")
	)
	(via
		(at 52.082446 -313.766708)
		(size 0.4572)
		(drill 0.2032)
		(layers "F.Cu" "B.Cu")
		(net "GND")
	)
	(via
		(at 264.729214 -292.516814)
		(size 0.4572)
		(drill 0.2032)
		(layers "F.Cu" "B.Cu")
		(net "GND")
	)
	(via
		(at 16.789146 -206.666592)
		(size 0.4572)
		(drill 0.2032)
		(layers "F.Cu" "B.Cu")
		(net "GND")
	)
	(via
		(at 37.969444 -126.69774)
		(size 0.508)
		(drill 0.254)
		(layers "F.Cu" "B.Cu")
		(net "GND")
	)
	(via
		(at 94.723966 -235.783882)
		(size 0.4572)
		(drill 0.2032)
		(layers "F.Cu" "B.Cu")
		(net "GND")
	)
	(via
		(at 205.180946 -212.616796)
		(size 0.4572)
		(drill 0.2032)
		(layers "F.Cu" "B.Cu")
		(net "GND")
	)
	(via
		(at 54.508146 -240.666778)
		(size 0.4572)
		(drill 0.2032)
		(layers "F.Cu" "B.Cu")
		(net "GND")
	)
	(via
		(at 264.729214 -287.416748)
		(size 0.4572)
		(drill 0.2032)
		(layers "F.Cu" "B.Cu")
		(net "GND")
	)
	(via
		(at 413.192214 -233.016806)
		(size 0.4572)
		(drill 0.2032)
		(layers "F.Cu" "B.Cu")
		(net "GND")
	)
	(via
		(at 57.404762 -168.86428)
		(size 0.508)
		(drill 0.254)
		(layers "F.Cu" "B.Cu")
		(net "GND")
	)
	(via
		(at 54.508146 -195.616576)
		(size 0.4572)
		(drill 0.2032)
		(layers "F.Cu" "B.Cu")
		(net "GND")
	)
	(via
		(at 259.075682 -196.466714)
		(size 0.4572)
		(drill 0.2032)
		(layers "F.Cu" "B.Cu")
		(net "GND")
	)
	(via
		(at 445.577214 -225.36658)
		(size 0.4572)
		(drill 0.2032)
		(layers "F.Cu" "B.Cu")
		(net "GND")
	)
	(via
		(at 289.250882 -239.81664)
		(size 0.4572)
		(drill 0.2032)
		(layers "F.Cu" "B.Cu")
		(net "GND")
	)
	(via
		(at 151.349964 -437.49976)
		(size 0.4572)
		(drill 0.2032)
		(layers "F.Cu" "B.Cu")
		(net "GND")
	)
	(via
		(at 365.877856 -332.363826)
		(size 0.508)
		(drill 0.254)
		(layers "F.Cu" "B.Cu")
		(net "GND")
	)
	(via
		(at 175.005746 -221.96679)
		(size 0.4572)
		(drill 0.2032)
		(layers "F.Cu" "B.Cu")
		(net "GND")
	)
	(via
		(at 63.942214 -194.766692)
		(size 0.4572)
		(drill 0.2032)
		(layers "F.Cu" "B.Cu")
		(net "GND")
	)
	(via
		(at 16.789146 -231.316784)
		(size 0.4572)
		(drill 0.2032)
		(layers "F.Cu" "B.Cu")
		(net "GND")
	)
	(via
		(at 415.369502 -401.492212)
		(size 0.4572)
		(drill 0.254)
		(layers "F.Cu" "B.Cu")
		(net "GND")
	)
	(via
		(at 262.519414 -250.016772)
		(size 0.4572)
		(drill 0.2032)
		(layers "F.Cu" "B.Cu")
		(net "GND")
	)
	(via
		(at 87.785194 -261.244842)
		(size 0.4572)
		(drill 0.2032)
		(layers "F.Cu" "B.Cu")
		(net "GND")
	)
	(via
		(at 342.773762 -268.569694)
		(size 0.4572)
		(drill 0.2032)
		(layers "F.Cu" "B.Cu")
		(net "GND")
	)
	(via
		(at 50.72888 -186.146948)
		(size 0.508)
		(drill 0.254)
		(layers "F.Cu" "B.Cu")
		(net "GND")
	)
	(via
		(at 7.035546 -227.066602)
		(size 0.4572)
		(drill 0.2032)
		(layers "F.Cu" "B.Cu")
		(net "GND")
	)
	(via
		(at 29.666692 -402.917152)
		(size 0.508)
		(drill 0.254)
		(layers "F.Cu" "B.Cu")
		(net "GND")
	)
	(via
		(at 48.4632 -171.618148)
		(size 0.508)
		(drill 0.254)
		(layers "F.Cu" "B.Cu")
		(net "GND")
	)
	(via
		(at 94.833694 -281.59202)
		(size 0.4572)
		(drill 0.2032)
		(layers "F.Cu" "B.Cu")
		(net "GND")
	)
	(via
		(at 287.360614 -289.11677)
		(size 0.4572)
		(drill 0.2032)
		(layers "F.Cu" "B.Cu")
		(net "GND")
	)
	(via
		(at 257.185414 -306.116736)
		(size 0.4572)
		(drill 0.2032)
		(layers "F.Cu" "B.Cu")
		(net "GND")
	)
	(via
		(at 291.460682 -215.166702)
		(size 0.4572)
		(drill 0.2032)
		(layers "F.Cu" "B.Cu")
		(net "GND")
	)
	(via
		(at 170.68927 -11.206226)
		(size 0.508)
		(drill 0.254)
		(layers "F.Cu" "B.Cu")
		(net "GND")
	)
	(via
		(at 164.018214 -299.316648)
		(size 0.4572)
		(drill 0.2032)
		(layers "F.Cu" "B.Cu")
		(net "GND")
	)
	(via
		(at 56.398414 -226.216718)
		(size 0.4572)
		(drill 0.2032)
		(layers "F.Cu" "B.Cu")
		(net "GND")
	)
	(via
		(at 447.467482 -228.766624)
		(size 0.4572)
		(drill 0.2032)
		(layers "F.Cu" "B.Cu")
		(net "GND")
	)
	(via
		(at 334.785462 -254.733552)
		(size 0.4318)
		(drill 0.2032)
		(layers "F.Cu" "B.Cu")
		(net "GND")
	)
	(via
		(at 357.340916 -266.128246)
		(size 0.4572)
		(drill 0.2032)
		(layers "F.Cu" "B.Cu")
		(net "GND")
	)
	(via
		(at 306.764182 -288.266632)
		(size 0.4572)
		(drill 0.2032)
		(layers "F.Cu" "B.Cu")
		(net "GND")
	)
	(via
		(at 296.794682 -308.666642)
		(size 0.4572)
		(drill 0.2032)
		(layers "F.Cu" "B.Cu")
		(net "GND")
	)
	(via
		(at 20.583652 -390.372346)
		(size 0.508)
		(drill 0.254)
		(layers "F.Cu" "B.Cu")
		(net "GND")
	)
	(via
		(at 311.882282 -230.466646)
		(size 0.4572)
		(drill 0.2032)
		(layers "F.Cu" "B.Cu")
		(net "GND")
	)
	(via
		(at 261.285482 -288.266632)
		(size 0.4572)
		(drill 0.2032)
		(layers "F.Cu" "B.Cu")
		(net "GND")
	)
	(via
		(at 18.679414 -204.116686)
		(size 0.4572)
		(drill 0.2032)
		(layers "F.Cu" "B.Cu")
		(net "GND")
	)
	(via
		(at 24.332946 -210.916774)
		(size 0.4572)
		(drill 0.2032)
		(layers "F.Cu" "B.Cu")
		(net "GND")
	)
	(via
		(at 302.448214 -304.416714)
		(size 0.4572)
		(drill 0.2032)
		(layers "F.Cu" "B.Cu")
		(net "GND")
	)
	(via
		(at 371.437916 -279.150318)
		(size 0.4572)
		(drill 0.2032)
		(layers "F.Cu" "B.Cu")
		(net "GND")
	)
	(via
		(at 309.992014 -283.166566)
		(size 0.4572)
		(drill 0.2032)
		(layers "F.Cu" "B.Cu")
		(net "GND")
	)
	(via
		(at 56.182514 -275.516594)
		(size 0.4572)
		(drill 0.2032)
		(layers "F.Cu" "B.Cu")
		(net "GND")
	)
	(via
		(at 346.423234 -226.017328)
		(size 0.4572)
		(drill 0.2032)
		(layers "F.Cu" "B.Cu")
		(net "GND")
	)
	(via
		(at 172.795946 -281.466798)
		(size 0.4572)
		(drill 0.2032)
		(layers "F.Cu" "B.Cu")
		(net "GND")
	)
	(via
		(at 357.700834 -219.506038)
		(size 0.4572)
		(drill 0.2032)
		(layers "F.Cu" "B.Cu")
		(net "GND")
	)
	(via
		(at 381.775716 -257.98907)
		(size 0.4572)
		(drill 0.2032)
		(layers "F.Cu" "B.Cu")
		(net "GND")
	)
	(via
		(at 264.729214 -210.916774)
		(size 0.4572)
		(drill 0.2032)
		(layers "F.Cu" "B.Cu")
		(net "GND")
	)
	(via
		(at 14.579346 -229.616762)
		(size 0.4572)
		(drill 0.2032)
		(layers "F.Cu" "B.Cu")
		(net "GND")
	)
	(via
		(at 435.823614 -234.716574)
		(size 0.4572)
		(drill 0.2032)
		(layers "F.Cu" "B.Cu")
		(net "GND")
	)
	(via
		(at 202.971146 -208.366614)
		(size 0.4572)
		(drill 0.2032)
		(layers "F.Cu" "B.Cu")
		(net "GND")
	)
	(via
		(at 119.596154 -403.883876)
		(size 0.4064)
		(drill 0.2032)
		(layers "F.Cu" "B.Cu")
		(net "GND")
	)
	(via
		(at 54.508146 -251.716794)
		(size 0.4572)
		(drill 0.2032)
		(layers "F.Cu" "B.Cu")
		(net "GND")
	)
	(via
		(at 445.577214 -279.766776)
		(size 0.4572)
		(drill 0.2032)
		(layers "F.Cu" "B.Cu")
		(net "GND")
	)
	(via
		(at 97.314258 -354.48494)
		(size 0.508)
		(drill 0.254)
		(layers "F.Cu" "B.Cu")
		(net "GND")
	)
	(via
		(at 88.250014 -432.747166)
		(size 0.4572)
		(drill 0.2032)
		(layers "F.Cu" "B.Cu")
		(net "GND")
	)
	(via
		(at 432.379882 -198.166736)
		(size 0.4572)
		(drill 0.2032)
		(layers "F.Cu" "B.Cu")
		(net "GND")
	)
	(via
		(at 130.30835 -156.398468)
		(size 0.508)
		(drill 0.254)
		(layers "F.Cu" "B.Cu")
		(net "GND")
	)
	(via
		(at 176.896014 -241.516662)
		(size 0.4572)
		(drill 0.2032)
		(layers "F.Cu" "B.Cu")
		(net "GND")
	)
	(via
		(at 346.532962 -283.219906)
		(size 0.4572)
		(drill 0.2032)
		(layers "F.Cu" "B.Cu")
		(net "GND")
	)
	(via
		(at 279.816814 -250.016772)
		(size 0.4572)
		(drill 0.2032)
		(layers "F.Cu" "B.Cu")
		(net "GND")
	)
	(via
		(at 390.58977 -410.030168)
		(size 0.4064)
		(drill 0.2032)
		(layers "F.Cu" "B.Cu")
		(net "GND")
	)
	(via
		(at 259.05714 -422.3258)
		(size 0.508)
		(drill 0.254)
		(layers "F.Cu" "B.Cu")
		(net "GND")
	)
	(via
		(at 67.146678 -410.030168)
		(size 0.4064)
		(drill 0.2032)
		(layers "F.Cu" "B.Cu")
		(net "GND")
	)
	(via
		(at 460.664814 -234.716574)
		(size 0.4572)
		(drill 0.2032)
		(layers "F.Cu" "B.Cu")
		(net "GND")
	)
	(via
		(at 371.608604 -332.570074)
		(size 0.49022)
		(drill 0.254)
		(layers "F.Cu" "B.Cu")
		(net "GND")
	)
	(via
		(at 373.92737 -400.858228)
		(size 0.4064)
		(drill 0.2032)
		(layers "F.Cu" "B.Cu")
		(net "GND")
	)
	(via
		(at 428.279814 -300.166786)
		(size 0.4572)
		(drill 0.2032)
		(layers "F.Cu" "B.Cu")
		(net "GND")
	)
	(via
		(at 392.34999 -436.051198)
		(size 0.4572)
		(drill 0.2032)
		(layers "F.Cu" "B.Cu")
		(net "GND")
	)
	(via
		(at 358.280462 -257.98907)
		(size 0.4572)
		(drill 0.2032)
		(layers "F.Cu" "B.Cu")
		(net "GND")
	)
	(via
		(at 201.737214 -233.86669)
		(size 0.4572)
		(drill 0.2032)
		(layers "F.Cu" "B.Cu")
		(net "GND")
	)
	(via
		(at 408.17292 -368.280188)
		(size 0.508)
		(drill 0.254)
		(layers "F.Cu" "B.Cu")
		(net "GND")
	)
	(via
		(at 292.694614 -300.166786)
		(size 0.4572)
		(drill 0.2032)
		(layers "F.Cu" "B.Cu")
		(net "GND")
	)
	(via
		(at 100.832666 -236.597952)
		(size 0.4572)
		(drill 0.2032)
		(layers "F.Cu" "B.Cu")
		(net "GND")
	)
	(via
		(at 409.413964 -441.225432)
		(size 0.508)
		(drill 0.254)
		(layers "F.Cu" "B.Cu")
		(net "GND")
	)
	(via
		(at 449.584318 -180.63845)
		(size 0.6604)
		(drill 0.3302)
		(layers "F.Cu" "B.Cu")
		(net "GND")
	)
	(via
		(at 57.956958 -410.030168)
		(size 0.4064)
		(drill 0.2032)
		(layers "F.Cu" "B.Cu")
		(net "GND")
	)
	(via
		(at 339.844634 -222.761556)
		(size 0.4572)
		(drill 0.2032)
		(layers "F.Cu" "B.Cu")
		(net "GND")
	)
	(via
		(at 52.298346 -250.016772)
		(size 0.4572)
		(drill 0.2032)
		(layers "F.Cu" "B.Cu")
		(net "GND")
	)
	(via
		(at 191.58966 -72.804528)
		(size 0.508)
		(drill 0.254)
		(layers "F.Cu" "B.Cu")
		(net "GND")
	)
	(via
		(at 274.163282 -278.916638)
		(size 0.4572)
		(drill 0.2032)
		(layers "F.Cu" "B.Cu")
		(net "GND")
	)
	(via
		(at 344.480642 -33.418526)
		(size 0.508)
		(drill 0.254)
		(layers "F.Cu" "B.Cu")
		(net "GND")
	)
	(via
		(at 104.911906 -335.704434)
		(size 0.49022)
		(drill 0.254)
		(layers "F.Cu" "B.Cu")
		(net "GND")
	)
	(via
		(at 104.51719 -333.355188)
		(size 0.49022)
		(drill 0.254)
		(layers "F.Cu" "B.Cu")
		(net "GND")
	)
	(via
		(at 376.201178 -353.84613)
		(size 0.508)
		(drill 0.254)
		(layers "F.Cu" "B.Cu")
		(net "GND")
	)
	(via
		(at 29.346906 -10.16508)
		(size 0.508)
		(drill 0.254)
		(layers "F.Cu" "B.Cu")
		(net "GND")
	)
	(via
		(at 314.092082 -244.066568)
		(size 0.4572)
		(drill 0.2032)
		(layers "F.Cu" "B.Cu")
		(net "GND")
	)
	(via
		(at 163.508944 -116.132356)
		(size 0.508)
		(drill 0.254)
		(layers "F.Cu" "B.Cu")
		(net "GND")
	)
	(via
		(at 32.682688 -4.328668)
		(size 0.508)
		(drill 0.254)
		(layers "F.Cu" "B.Cu")
		(net "GND")
	)
	(via
		(at 13.345414 -226.216718)
		(size 0.4572)
		(drill 0.2032)
		(layers "F.Cu" "B.Cu")
		(net "GND")
	)
	(via
		(at 317.973964 -441.225432)
		(size 0.508)
		(drill 0.254)
		(layers "F.Cu" "B.Cu")
		(net "GND")
	)
	(via
		(at 283.916882 -303.566576)
		(size 0.4572)
		(drill 0.2032)
		(layers "F.Cu" "B.Cu")
		(net "GND")
	)
	(via
		(at 116.415058 -330.55052)
		(size 0.508)
		(drill 0.254)
		(layers "F.Cu" "B.Cu")
		(net "GND")
	)
	(via
		(at 161.808414 -228.766624)
		(size 0.4572)
		(drill 0.2032)
		(layers "F.Cu" "B.Cu")
		(net "GND")
	)
	(via
		(at 142.746222 -406.370536)
		(size 0.4572)
		(drill 0.254)
		(layers "F.Cu" "B.Cu")
		(net "GND")
	)
	(via
		(at 77.173074 -341.595964)
		(size 0.508)
		(drill 0.254)
		(layers "F.Cu" "B.Cu")
		(net "GND")
	)
	(via
		(at 22.264116 -95.510604)
		(size 0.508)
		(drill 0.254)
		(layers "F.Cu" "B.Cu")
		(net "GND")
	)
	(via
		(at 7.035546 -272.116804)
		(size 0.4572)
		(drill 0.2032)
		(layers "F.Cu" "B.Cu")
		(net "GND")
	)
	(via
		(at 164.018214 -194.766692)
		(size 0.4572)
		(drill 0.2032)
		(layers "F.Cu" "B.Cu")
		(net "GND")
	)
	(via
		(at 345.483434 -239.0394)
		(size 0.4572)
		(drill 0.2032)
		(layers "F.Cu" "B.Cu")
		(net "GND")
	)
	(via
		(at 126.207012 -241.481102)
		(size 0.4572)
		(drill 0.2032)
		(layers "F.Cu" "B.Cu")
		(net "GND")
	)
	(via
		(at 370.498116 -271.011396)
		(size 0.4572)
		(drill 0.2032)
		(layers "F.Cu" "B.Cu")
		(net "GND")
	)
	(via
		(at 352.062034 -226.017328)
		(size 0.4572)
		(drill 0.2032)
		(layers "F.Cu" "B.Cu")
		(net "GND")
	)
	(via
		(at 214.615014 -312.91657)
		(size 0.4572)
		(drill 0.2032)
		(layers "F.Cu" "B.Cu")
		(net "GND")
	)
	(via
		(at 372.84533 -400.858228)
		(size 0.4064)
		(drill 0.2032)
		(layers "F.Cu" "B.Cu")
		(net "GND")
	)
	(via
		(at 424.836082 -232.166668)
		(size 0.4572)
		(drill 0.2032)
		(layers "F.Cu" "B.Cu")
		(net "GND")
	)
	(via
		(at 23.0378 -71.821548)
		(size 0.508)
		(drill 0.254)
		(layers "F.Cu" "B.Cu")
		(net "GND")
	)
	(via
		(at 205.180946 -197.316598)
		(size 0.4572)
		(drill 0.2032)
		(layers "F.Cu" "B.Cu")
		(net "GND")
	)
	(via
		(at 268.829282 -228.766624)
		(size 0.4572)
		(drill 0.2032)
		(layers "F.Cu" "B.Cu")
		(net "GND")
	)
	(via
		(at 96.133412 -244.73662)
		(size 0.4572)
		(drill 0.2032)
		(layers "F.Cu" "B.Cu")
		(net "GND")
	)
	(via
		(at 101.412294 -278.336502)
		(size 0.4572)
		(drill 0.2032)
		(layers "F.Cu" "B.Cu")
		(net "GND")
	)
	(via
		(at 102.882192 -236.426248)
		(size 0.4572)
		(drill 0.2032)
		(layers "F.Cu" "B.Cu")
		(net "GND")
	)
	(via
		(at 39.420546 -238.966756)
		(size 0.4572)
		(drill 0.2032)
		(layers "F.Cu" "B.Cu")
		(net "GND")
	)
	(via
		(at 132.350002 -434.899562)
		(size 0.4572)
		(drill 0.2032)
		(layers "F.Cu" "B.Cu")
		(net "GND")
	)
	(via
		(at 456.8063 -387.30682)
		(size 0.508)
		(drill 0.254)
		(layers "F.Cu" "B.Cu")
		(net "GND")
	)
	(via
		(at 98.593148 -281.59202)
		(size 0.4572)
		(drill 0.2032)
		(layers "F.Cu" "B.Cu")
		(net "GND")
	)
	(via
		(at 353.533964 -441.225432)
		(size 0.508)
		(drill 0.254)
		(layers "F.Cu" "B.Cu")
		(net "GND")
	)
	(via
		(at 380.365762 -262.058658)
		(size 0.4572)
		(drill 0.2032)
		(layers "F.Cu" "B.Cu")
		(net "GND")
	)
	(via
		(at 51.235864 -4.962652)
		(size 0.508)
		(drill 0.254)
		(layers "F.Cu" "B.Cu")
		(net "GND")
	)
	(via
		(at 338.434934 -239.853216)
		(size 0.4572)
		(drill 0.2032)
		(layers "F.Cu" "B.Cu")
		(net "GND")
	)
	(via
		(at 164.462714 -400.834352)
		(size 0.4064)
		(drill 0.2032)
		(layers "F.Cu" "B.Cu")
		(net "GND")
	)
	(via
		(at 344.25001 -436.347362)
		(size 0.4572)
		(drill 0.2032)
		(layers "F.Cu" "B.Cu")
		(net "GND")
	)
	(via
		(at 208.520284 -323.434456)
		(size 0.4572)
		(drill 0.2032)
		(layers "F.Cu" "B.Cu")
		(net "GND")
	)
	(via
		(at 281.707082 -250.866656)
		(size 0.4572)
		(drill 0.2032)
		(layers "F.Cu" "B.Cu")
		(net "GND")
	)
	(via
		(at 94.98965 -401.492212)
		(size 0.4572)
		(drill 0.254)
		(layers "F.Cu" "B.Cu")
		(net "GND")
	)
	(via
		(at 335.725262 -269.38351)
		(size 0.4572)
		(drill 0.2032)
		(layers "F.Cu" "B.Cu")
		(net "GND")
	)
	(via
		(at 314.592208 -400.858228)
		(size 0.4064)
		(drill 0.2032)
		(layers "F.Cu" "B.Cu")
		(net "GND")
	)
	(via
		(at 131.803902 -336.766662)
		(size 0.49022)
		(drill 0.254)
		(layers "F.Cu" "B.Cu")
		(net "GND")
	)
	(via
		(at 106.111548 -279.964134)
		(size 0.4572)
		(drill 0.2032)
		(layers "F.Cu" "B.Cu")
		(net "GND")
	)
	(via
		(at 158.968948 -48.576992)
		(size 0.508)
		(drill 0.254)
		(layers "F.Cu" "B.Cu")
		(net "GND")
	)
	(via
		(at 369.088162 -289.807142)
		(size 0.4572)
		(drill 0.2032)
		(layers "F.Cu" "B.Cu")
		(net "GND")
	)
	(via
		(at 432.014884 -115.797076)
		(size 0.508)
		(drill 0.254)
		(layers "F.Cu" "B.Cu")
		(net "GND")
	)
	(via
		(at 18.679414 -222.816674)
		(size 0.4572)
		(drill 0.2032)
		(layers "F.Cu" "B.Cu")
		(net "GND")
	)
	(via
		(at 413.74949 -403.883876)
		(size 0.4064)
		(drill 0.2032)
		(layers "F.Cu" "B.Cu")
		(net "GND")
	)
	(via
		(at 453.121014 -206.666592)
		(size 0.4572)
		(drill 0.2032)
		(layers "F.Cu" "B.Cu")
		(net "GND")
	)
	(via
		(at 339.484462 -275.8948)
		(size 0.4572)
		(drill 0.2032)
		(layers "F.Cu" "B.Cu")
		(net "GND")
	)
	(via
		(at 52.298346 -285.716726)
		(size 0.4572)
		(drill 0.2032)
		(layers "F.Cu" "B.Cu")
		(net "GND")
	)
	(via
		(at 420.736014 -244.916706)
		(size 0.4572)
		(drill 0.2032)
		(layers "F.Cu" "B.Cu")
		(net "GND")
	)
	(via
		(at 180.339746 -270.416782)
		(size 0.4572)
		(drill 0.2032)
		(layers "F.Cu" "B.Cu")
		(net "GND")
	)
	(via
		(at 115.039394 -269.38351)
		(size 0.4572)
		(drill 0.2032)
		(layers "F.Cu" "B.Cu")
		(net "GND")
	)
	(via
		(at 14.579346 -212.616796)
		(size 0.4572)
		(drill 0.2032)
		(layers "F.Cu" "B.Cu")
		(net "GND")
	)
	(via
		(at 86.375494 -278.336502)
		(size 0.4318)
		(drill 0.2032)
		(layers "F.Cu" "B.Cu")
		(net "GND")
	)
	(via
		(at 406.752552 -323.378576)
		(size 0.4572)
		(drill 0.2032)
		(layers "F.Cu" "B.Cu")
		(net "GND")
	)
	(via
		(at 274.163282 -241.516662)
		(size 0.4572)
		(drill 0.2032)
		(layers "F.Cu" "B.Cu")
		(net "GND")
	)
	(via
		(at 304.338482 -316.316614)
		(size 0.4572)
		(drill 0.2032)
		(layers "F.Cu" "B.Cu")
		(net "GND")
	)
	(via
		(at 336.085434 -217.878406)
		(size 0.4572)
		(drill 0.2032)
		(layers "F.Cu" "B.Cu")
		(net "GND")
	)
	(via
		(at 66.152014 -278.916638)
		(size 0.4572)
		(drill 0.2032)
		(layers "F.Cu" "B.Cu")
		(net "GND")
	)
	(via
		(at 18.679414 -196.466714)
		(size 0.4572)
		(drill 0.2032)
		(layers "F.Cu" "B.Cu")
		(net "GND")
	)
	(via
		(at 108.43387 -248.421144)
		(size 0.4572)
		(drill 0.2032)
		(layers "F.Cu" "B.Cu")
		(net "GND")
	)
	(via
		(at 180.155596 -115.775486)
		(size 0.4572)
		(drill 0.254)
		(layers "F.Cu" "B.Cu")
		(net "GND")
	)
	(via
		(at 26.138886 -164.827204)
		(size 0.508)
		(drill 0.254)
		(layers "F.Cu" "B.Cu")
		(net "GND")
	)
	(via
		(at 110.23092 -244.736874)
		(size 0.4572)
		(drill 0.2032)
		(layers "F.Cu" "B.Cu")
		(net "GND")
	)
	(via
		(at 357.609902 -297.197526)
		(size 0.508)
		(drill 0.254)
		(layers "F.Cu" "B.Cu")
		(net "GND")
	)
	(via
		(at 87.507318 -407.00452)
		(size 0.4064)
		(drill 0.2032)
		(layers "F.Cu" "B.Cu")
		(net "GND")
	)
	(via
		(at 442.133482 -299.316648)
		(size 0.4572)
		(drill 0.2032)
		(layers "F.Cu" "B.Cu")
		(net "GND")
	)
	(via
		(at 150.589742 -403.249892)
		(size 0.4572)
		(drill 0.254)
		(layers "F.Cu" "B.Cu")
		(net "GND")
	)
	(via
		(at 111.170212 -231.714548)
		(size 0.4572)
		(drill 0.2032)
		(layers "F.Cu" "B.Cu")
		(net "GND")
	)
	(via
		(at 281.707082 -230.466646)
		(size 0.4572)
		(drill 0.2032)
		(layers "F.Cu" "B.Cu")
		(net "GND")
	)
	(via
		(at 372.26748 -228.45903)
		(size 0.4572)
		(drill 0.2032)
		(layers "F.Cu" "B.Cu")
		(net "GND")
	)
	(via
		(at 279.816814 -270.416782)
		(size 0.4572)
		(drill 0.2032)
		(layers "F.Cu" "B.Cu")
		(net "GND")
	)
	(via
		(at 56.83885 -146.489674)
		(size 0.49022)
		(drill 0.254)
		(layers "F.Cu" "B.Cu")
		(net "GND")
	)
	(via
		(at 307.782214 -258.516628)
		(size 0.4572)
		(drill 0.2032)
		(layers "F.Cu" "B.Cu")
		(net "GND")
	)
	(via
		(at 22.123146 -212.616796)
		(size 0.4572)
		(drill 0.2032)
		(layers "F.Cu" "B.Cu")
		(net "GND")
	)
	(via
		(at 363.809534 -217.064336)
		(size 0.4572)
		(drill 0.2032)
		(layers "F.Cu" "B.Cu")
		(net "GND")
	)
	(via
		(at 136.544812 -234.970066)
		(size 0.4572)
		(drill 0.2032)
		(layers "F.Cu" "B.Cu")
		(net "GND")
	)
	(via
		(at 372.26748 -230.086662)
		(size 0.4572)
		(drill 0.2032)
		(layers "F.Cu" "B.Cu")
		(net "GND")
	)
	(via
		(at 95.193866 -213.732618)
		(size 0.4572)
		(drill 0.2032)
		(layers "F.Cu" "B.Cu")
		(net "GND")
	)
	(via
		(at 187.883546 -317.166752)
		(size 0.4572)
		(drill 0.2032)
		(layers "F.Cu" "B.Cu")
		(net "GND")
	)
	(via
		(at 411.958282 -301.01667)
		(size 0.4572)
		(drill 0.2032)
		(layers "F.Cu" "B.Cu")
		(net "GND")
	)
	(via
		(at 58.318146 -406.370536)
		(size 0.4572)
		(drill 0.254)
		(layers "F.Cu" "B.Cu")
		(net "GND")
	)
	(via
		(at 287.360614 -217.716608)
		(size 0.4572)
		(drill 0.2032)
		(layers "F.Cu" "B.Cu")
		(net "GND")
	)
	(via
		(at 364.859062 -264.50036)
		(size 0.4572)
		(drill 0.2032)
		(layers "F.Cu" "B.Cu")
		(net "GND")
	)
	(via
		(at 158.336234 -403.883876)
		(size 0.4064)
		(drill 0.2032)
		(layers "F.Cu" "B.Cu")
		(net "GND")
	)
	(via
		(at 379.896116 -279.150318)
		(size 0.4572)
		(drill 0.2032)
		(layers "F.Cu" "B.Cu")
		(net "GND")
	)
	(via
		(at 66.367914 -284.866588)
		(size 0.4572)
		(drill 0.2032)
		(layers "F.Cu" "B.Cu")
		(net "GND")
	)
	(via
		(at 205.180946 -225.36658)
		(size 0.4572)
		(drill 0.2032)
		(layers "F.Cu" "B.Cu")
		(net "GND")
	)
	(via
		(at 338.904834 -239.0394)
		(size 0.4572)
		(drill 0.2032)
		(layers "F.Cu" "B.Cu")
		(net "GND")
	)
	(via
		(at 356.291134 -217.064336)
		(size 0.4572)
		(drill 0.2032)
		(layers "F.Cu" "B.Cu")
		(net "GND")
	)
	(via
		(at 244.389148 -135.92302)
		(size 0.508)
		(drill 0.254)
		(layers "F.Cu" "B.Cu")
		(net "GND")
	)
	(via
		(at 285.150814 -283.166566)
		(size 0.4572)
		(drill 0.2032)
		(layers "F.Cu" "B.Cu")
		(net "GND")
	)
	(via
		(at 48.638714 -312.91657)
		(size 0.4572)
		(drill 0.2032)
		(layers "F.Cu" "B.Cu")
		(net "GND")
	)
	(via
		(at 380.366016 -273.453098)
		(size 0.4572)
		(drill 0.2032)
		(layers "F.Cu" "B.Cu")
		(net "GND")
	)
	(via
		(at 62.051946 -223.666558)
		(size 0.4572)
		(drill 0.2032)
		(layers "F.Cu" "B.Cu")
		(net "GND")
	)
	(via
		(at 134.2136 -26.47315)
		(size 0.508)
		(drill 0.254)
		(layers "F.Cu" "B.Cu")
		(net "GND")
	)
	(via
		(at 51.064414 -299.316648)
		(size 0.4572)
		(drill 0.2032)
		(layers "F.Cu" "B.Cu")
		(net "GND")
	)
	(via
		(at 344.950796 -407.638504)
		(size 0.4572)
		(drill 0.254)
		(layers "F.Cu" "B.Cu")
		(net "GND")
	)
	(via
		(at 422.945814 -231.316784)
		(size 0.4572)
		(drill 0.2032)
		(layers "F.Cu" "B.Cu")
		(net "GND")
	)
	(via
		(at 308.191916 -409.396184)
		(size 0.4572)
		(drill 0.254)
		(layers "F.Cu" "B.Cu")
		(net "GND")
	)
	(via
		(at 7.035546 -313.766708)
		(size 0.4572)
		(drill 0.2032)
		(layers "F.Cu" "B.Cu")
		(net "GND")
	)
	(via
		(at 22.123146 -229.616762)
		(size 0.4572)
		(drill 0.2032)
		(layers "F.Cu" "B.Cu")
		(net "GND")
	)
	(via
		(at 66.152014 -204.116686)
		(size 0.4572)
		(drill 0.2032)
		(layers "F.Cu" "B.Cu")
		(net "GND")
	)
	(via
		(at 204.8002 -71.034148)
		(size 0.508)
		(drill 0.254)
		(layers "F.Cu" "B.Cu")
		(net "GND")
	)
	(via
		(at 415.402014 -214.316564)
		(size 0.4572)
		(drill 0.2032)
		(layers "F.Cu" "B.Cu")
		(net "GND")
	)
	(via
		(at 122.447812 -228.45903)
		(size 0.4572)
		(drill 0.2032)
		(layers "F.Cu" "B.Cu")
		(net "GND")
	)
	(via
		(at 191.983614 -261.066788)
		(size 0.4572)
		(drill 0.2032)
		(layers "F.Cu" "B.Cu")
		(net "GND")
	)
	(via
		(at 409.748482 -264.466578)
		(size 0.4572)
		(drill 0.2032)
		(layers "F.Cu" "B.Cu")
		(net "GND")
	)
	(via
		(at 172.043598 -353.19335)
		(size 0.49022)
		(drill 0.254)
		(layers "F.Cu" "B.Cu")
		(net "GND")
	)
	(via
		(at 176.896014 -289.966654)
		(size 0.4572)
		(drill 0.2032)
		(layers "F.Cu" "B.Cu")
		(net "GND")
	)
	(via
		(at 388.607808 -340.284816)
		(size 0.508)
		(drill 0.254)
		(layers "F.Cu" "B.Cu")
		(net "GND")
	)
	(via
		(at 360.050334 -217.064336)
		(size 0.4572)
		(drill 0.2032)
		(layers "F.Cu" "B.Cu")
		(net "GND")
	)
	(via
		(at 262.519414 -283.166566)
		(size 0.4572)
		(drill 0.2032)
		(layers "F.Cu" "B.Cu")
		(net "GND")
	)
	(via
		(at 123.497594 -272.639282)
		(size 0.4572)
		(drill 0.2032)
		(layers "F.Cu" "B.Cu")
		(net "GND")
	)
	(via
		(at 364.854744 -76.281026)
		(size 0.508)
		(drill 0.254)
		(layers "F.Cu" "B.Cu")
		(net "GND")
	)
	(via
		(at 156.716222 -404.51786)
		(size 0.4572)
		(drill 0.254)
		(layers "F.Cu" "B.Cu")
		(net "GND")
	)
	(via
		(at 447.141092 -71.005192)
		(size 0.508)
		(drill 0.254)
		(layers "F.Cu" "B.Cu")
		(net "GND")
	)
	(via
		(at 309.992014 -270.416782)
		(size 0.4572)
		(drill 0.2032)
		(layers "F.Cu" "B.Cu")
		(net "GND")
	)
	(via
		(at 138.336782 -404.51786)
		(size 0.4572)
		(drill 0.254)
		(layers "F.Cu" "B.Cu")
		(net "GND")
	)
	(via
		(at 342.194134 -231.714548)
		(size 0.4572)
		(drill 0.2032)
		(layers "F.Cu" "B.Cu")
		(net "GND")
	)
	(via
		(at 191.983614 -295.916604)
		(size 0.4572)
		(drill 0.2032)
		(layers "F.Cu" "B.Cu")
		(net "GND")
	)
	(via
		(at 380.835662 -284.033722)
		(size 0.4572)
		(drill 0.2032)
		(layers "F.Cu" "B.Cu")
		(net "GND")
	)
	(via
		(at 199.527414 -294.216582)
		(size 0.4572)
		(drill 0.2032)
		(layers "F.Cu" "B.Cu")
		(net "GND")
	)
	(via
		(at 130.350006 -432.747166)
		(size 0.4572)
		(drill 0.2032)
		(layers "F.Cu" "B.Cu")
		(net "GND")
	)
	(via
		(at 446.659 -59.644788)
		(size 0.508)
		(drill 0.254)
		(layers "F.Cu" "B.Cu")
		(net "GND")
	)
	(via
		(at 411.958282 -200.716642)
		(size 0.4572)
		(drill 0.2032)
		(layers "F.Cu" "B.Cu")
		(net "GND")
	)
	(via
		(at 21.80209 -182.384446)
		(size 0.508)
		(drill 0.254)
		(layers "F.Cu" "B.Cu")
		(net "GND")
	)
	(via
		(at 289.250882 -308.666642)
		(size 0.4572)
		(drill 0.2032)
		(layers "F.Cu" "B.Cu")
		(net "GND")
	)
	(via
		(at 24.332946 -201.56678)
		(size 0.4572)
		(drill 0.2032)
		(layers "F.Cu" "B.Cu")
		(net "GND")
	)
	(via
		(at 37.210746 -216.016586)
		(size 0.4572)
		(drill 0.2032)
		(layers "F.Cu" "B.Cu")
		(net "GND")
	)
	(via
		(at 185.663078 -17.655032)
		(size 0.508)
		(drill 0.254)
		(layers "F.Cu" "B.Cu")
		(net "GND")
	)
	(via
		(at 29.666946 -206.666592)
		(size 0.4572)
		(drill 0.2032)
		(layers "F.Cu" "B.Cu")
		(net "GND")
	)
	(via
		(at 416.81273 -400.858228)
		(size 0.4064)
		(drill 0.2032)
		(layers "F.Cu" "B.Cu")
		(net "GND")
	)
	(via
		(at 2.764536 -234.110022)
		(size 0.508)
		(drill 0.254)
		(layers "F.Cu" "B.Cu")
		(net "GND")
	)
	(via
		(at 52.911248 -164.86759)
		(size 0.49022)
		(drill 0.254)
		(layers "F.Cu" "B.Cu")
		(net "GND")
	)
	(via
		(at 371.437662 -287.28924)
		(size 0.4572)
		(drill 0.2032)
		(layers "F.Cu" "B.Cu")
		(net "GND")
	)
	(via
		(at 256.97688 -149.697948)
		(size 0.508)
		(drill 0.254)
		(layers "F.Cu" "B.Cu")
		(net "GND")
	)
	(via
		(at 46.964346 -307.816758)
		(size 0.4572)
		(drill 0.2032)
		(layers "F.Cu" "B.Cu")
		(net "GND")
	)
	(via
		(at 109.95533 -441.225432)
		(size 0.508)
		(drill 0.254)
		(layers "F.Cu" "B.Cu")
		(net "GND")
	)
	(via
		(at 283.916882 -297.616626)
		(size 0.4572)
		(drill 0.2032)
		(layers "F.Cu" "B.Cu")
		(net "GND")
	)
	(via
		(at 96.133412 -249.620024)
		(size 0.4572)
		(drill 0.2032)
		(layers "F.Cu" "B.Cu")
		(net "GND")
	)
	(via
		(at 386.474462 -277.522432)
		(size 0.4572)
		(drill 0.2032)
		(layers "F.Cu" "B.Cu")
		(net "GND")
	)
	(via
		(at 104.591866 -223.575626)
		(size 0.4572)
		(drill 0.2032)
		(layers "F.Cu" "B.Cu")
		(net "GND")
	)
	(via
		(at 338.900008 -49.650396)
		(size 0.4572)
		(drill 0.2032)
		(layers "F.Cu" "B.Cu")
		(net "GND")
	)
	(via
		(at 184.439814 -226.216718)
		(size 0.4572)
		(drill 0.2032)
		(layers "F.Cu" "B.Cu")
		(net "GND")
	)
	(via
		(at 46.964346 -278.066754)
		(size 0.4572)
		(drill 0.2032)
		(layers "F.Cu" "B.Cu")
		(net "GND")
	)
	(via
		(at 375.447306 -178.915568)
		(size 0.508)
		(drill 0.254)
		(layers "F.Cu" "B.Cu")
		(net "GND")
	)
	(via
		(at 264.729214 -315.46673)
		(size 0.4572)
		(drill 0.2032)
		(layers "F.Cu" "B.Cu")
		(net "GND")
	)
	(via
		(at 414.070292 -169.380154)
		(size 0.49022)
		(drill 0.254)
		(layers "F.Cu" "B.Cu")
		(net "GND")
	)
	(via
		(at 31.876746 -307.816758)
		(size 0.4572)
		(drill 0.2032)
		(layers "F.Cu" "B.Cu")
		(net "GND")
	)
	(via
		(at 411.355286 -165.727126)
		(size 0.508)
		(drill 0.254)
		(layers "F.Cu" "B.Cu")
		(net "GND")
	)
	(via
		(at 287.360614 -272.116804)
		(size 0.4572)
		(drill 0.2032)
		(layers "F.Cu" "B.Cu")
		(net "GND")
	)
	(via
		(at 165.048946 -273.816572)
		(size 0.4572)
		(drill 0.2032)
		(layers "F.Cu" "B.Cu")
		(net "GND")
	)
	(via
		(at 58.608214 -222.816674)
		(size 0.4572)
		(drill 0.2032)
		(layers "F.Cu" "B.Cu")
		(net "GND")
	)
	(via
		(at 94.833694 -279.964134)
		(size 0.4572)
		(drill 0.2032)
		(layers "F.Cu" "B.Cu")
		(net "GND")
	)
	(via
		(at 315.250068 -432.747166)
		(size 0.4572)
		(drill 0.2032)
		(layers "F.Cu" "B.Cu")
		(net "GND")
	)
	(via
		(at 182.549546 -212.616796)
		(size 0.4572)
		(drill 0.2032)
		(layers "F.Cu" "B.Cu")
		(net "GND")
	)
	(via
		(at 352.697288 -410.030168)
		(size 0.4064)
		(drill 0.2032)
		(layers "F.Cu" "B.Cu")
		(net "GND")
	)
	(via
		(at 41.792652 -4.328668)
		(size 0.508)
		(drill 0.254)
		(layers "F.Cu" "B.Cu")
		(net "GND")
	)
	(via
		(at 209.281014 -250.866656)
		(size 0.4572)
		(drill 0.2032)
		(layers "F.Cu" "B.Cu")
		(net "GND")
	)
	(via
		(at 137.014712 -219.506038)
		(size 0.4572)
		(drill 0.2032)
		(layers "F.Cu" "B.Cu")
		(net "GND")
	)
	(via
		(at 136.184894 -268.569694)
		(size 0.4572)
		(drill 0.2032)
		(layers "F.Cu" "B.Cu")
		(net "GND")
	)
	(via
		(at 418.15893 -410.030168)
		(size 0.4064)
		(drill 0.2032)
		(layers "F.Cu" "B.Cu")
		(net "GND")
	)
	(via
		(at 306.3875 -410.664152)
		(size 0.4572)
		(drill 0.254)
		(layers "F.Cu" "B.Cu")
		(net "GND")
	)
	(via
		(at 314.23102 -403.249892)
		(size 0.4572)
		(drill 0.254)
		(layers "F.Cu" "B.Cu")
		(net "GND")
	)
	(via
		(at 386.350002 -429.147224)
		(size 0.4572)
		(drill 0.2032)
		(layers "F.Cu" "B.Cu")
		(net "GND")
	)
	(via
		(at 413.192214 -251.716794)
		(size 0.4572)
		(drill 0.2032)
		(layers "F.Cu" "B.Cu")
		(net "GND")
	)
	(via
		(at 287.360614 -210.916774)
		(size 0.4572)
		(drill 0.2032)
		(layers "F.Cu" "B.Cu")
		(net "GND")
	)
	(via
		(at 417.292282 -278.916638)
		(size 0.4572)
		(drill 0.2032)
		(layers "F.Cu" "B.Cu")
		(net "GND")
	)
	(via
		(at 197.637146 -290.816792)
		(size 0.4572)
		(drill 0.2032)
		(layers "F.Cu" "B.Cu")
		(net "GND")
	)
	(via
		(at 88.950546 -406.370536)
		(size 0.4572)
		(drill 0.254)
		(layers "F.Cu" "B.Cu")
		(net "GND")
	)
	(via
		(at 404.920958 -403.249892)
		(size 0.4572)
		(drill 0.254)
		(layers "F.Cu" "B.Cu")
		(net "GND")
	)
	(via
		(at 13.345414 -228.766624)
		(size 0.4572)
		(drill 0.2032)
		(layers "F.Cu" "B.Cu")
		(net "GND")
	)
	(via
		(at 136.184894 -255.547622)
		(size 0.4318)
		(drill 0.2032)
		(layers "F.Cu" "B.Cu")
		(net "GND")
	)
	(via
		(at 442.133482 -264.466578)
		(size 0.4572)
		(drill 0.2032)
		(layers "F.Cu" "B.Cu")
		(net "GND")
	)
	(via
		(at 65.25006 -433.747164)
		(size 0.4572)
		(drill 0.2032)
		(layers "F.Cu" "B.Cu")
		(net "GND")
	)
	(via
		(at 432.379882 -306.96662)
		(size 0.4572)
		(drill 0.2032)
		(layers "F.Cu" "B.Cu")
		(net "GND")
	)
	(via
		(at 102.242366 -222.761556)
		(size 0.4572)
		(drill 0.2032)
		(layers "F.Cu" "B.Cu")
		(net "GND")
	)
	(via
		(at 376.703336 -337.692238)
		(size 0.49022)
		(drill 0.254)
		(layers "F.Cu" "B.Cu")
		(net "GND")
	)
	(via
		(at 180.155596 -110.975394)
		(size 0.4572)
		(drill 0.254)
		(layers "F.Cu" "B.Cu")
		(net "GND")
	)
	(via
		(at 16.789146 -309.51678)
		(size 0.4572)
		(drill 0.2032)
		(layers "F.Cu" "B.Cu")
		(net "GND")
	)
	(via
		(at 157.708346 -246.616728)
		(size 0.4572)
		(drill 0.2032)
		(layers "F.Cu" "B.Cu")
		(net "GND")
	)
	(via
		(at 214.087456 -28.015184)
		(size 0.508)
		(drill 0.254)
		(layers "F.Cu" "B.Cu")
		(net "GND")
	)
	(via
		(at 66.152014 -194.766692)
		(size 0.4572)
		(drill 0.2032)
		(layers "F.Cu" "B.Cu")
		(net "GND")
	)
	(via
		(at 157.708346 -268.71676)
		(size 0.4572)
		(drill 0.2032)
		(layers "F.Cu" "B.Cu")
		(net "GND")
	)
	(via
		(at 336.665062 -262.872474)
		(size 0.4572)
		(drill 0.2032)
		(layers "F.Cu" "B.Cu")
		(net "GND")
	)
	(via
		(at 89.664794 -287.28924)
		(size 0.4572)
		(drill 0.2032)
		(layers "F.Cu" "B.Cu")
		(net "GND")
	)
	(via
		(at 18.679414 -316.316614)
		(size 0.4572)
		(drill 0.2032)
		(layers "F.Cu" "B.Cu")
		(net "GND")
	)
	(via
		(at 28.433014 -266.1666)
		(size 0.4572)
		(drill 0.2032)
		(layers "F.Cu" "B.Cu")
		(net "GND")
	)
	(via
		(at 124.907548 -279.964134)
		(size 0.4572)
		(drill 0.2032)
		(layers "F.Cu" "B.Cu")
		(net "GND")
	)
	(via
		(at 455.011282 -288.266632)
		(size 0.4572)
		(drill 0.2032)
		(layers "F.Cu" "B.Cu")
		(net "GND")
	)
	(via
		(at 335.784444 -60.128404)
		(size 0.4572)
		(drill 0.2032)
		(layers "F.Cu" "B.Cu")
		(net "GND")
	)
	(via
		(at 157.708346 -309.51678)
		(size 0.4572)
		(drill 0.2032)
		(layers "F.Cu" "B.Cu")
		(net "GND")
	)
	(via
		(at 261.285482 -271.266666)
		(size 0.4572)
		(drill 0.2032)
		(layers "F.Cu" "B.Cu")
		(net "GND")
	)
	(via
		(at 45.657008 -12.37488)
		(size 0.508)
		(drill 0.254)
		(layers "F.Cu" "B.Cu")
		(net "GND")
	)
	(via
		(at 101.302566 -216.25052)
		(size 0.4572)
		(drill 0.2032)
		(layers "F.Cu" "B.Cu")
		(net "GND")
	)
	(via
		(at 52.911248 -163.60775)
		(size 0.49022)
		(drill 0.254)
		(layers "F.Cu" "B.Cu")
		(net "GND")
	)
	(via
		(at 341.282274 -338.472272)
		(size 0.508)
		(drill 0.254)
		(layers "F.Cu" "B.Cu")
		(net "GND")
	)
	(via
		(at 283.916882 -305.266598)
		(size 0.4572)
		(drill 0.2032)
		(layers "F.Cu" "B.Cu")
		(net "GND")
	)
	(via
		(at 136.545066 -241.481102)
		(size 0.4318)
		(drill 0.2032)
		(layers "F.Cu" "B.Cu")
		(net "GND")
	)
	(via
		(at 202.971146 -292.516814)
		(size 0.4572)
		(drill 0.2032)
		(layers "F.Cu" "B.Cu")
		(net "GND")
	)
	(via
		(at 339.374734 -213.732618)
		(size 0.4572)
		(drill 0.2032)
		(layers "F.Cu" "B.Cu")
		(net "GND")
	)
	(via
		(at 415.630614 -285.716726)
		(size 0.4572)
		(drill 0.2032)
		(layers "F.Cu" "B.Cu")
		(net "GND")
	)
	(via
		(at 262.519414 -231.316784)
		(size 0.4572)
		(drill 0.2032)
		(layers "F.Cu" "B.Cu")
		(net "GND")
	)
	(via
		(at 295.275 -48.504348)
		(size 0.508)
		(drill 0.254)
		(layers "F.Cu" "B.Cu")
		(net "GND")
	)
	(via
		(at 311.882282 -226.216718)
		(size 0.4572)
		(drill 0.2032)
		(layers "F.Cu" "B.Cu")
		(net "GND")
	)
	(via
		(at 343.549478 -45.630592)
		(size 0.4572)
		(drill 0.2032)
		(layers "F.Cu" "B.Cu")
		(net "GND")
	)
	(via
		(at 32.30753 -424.271948)
		(size 0.508)
		(drill 0.254)
		(layers "F.Cu" "B.Cu")
		(net "GND")
	)
	(via
		(at 192.74282 -425.405042)
		(size 0.508)
		(drill 0.254)
		(layers "F.Cu" "B.Cu")
		(net "GND")
	)
	(via
		(at 133.255766 -227.64496)
		(size 0.4572)
		(drill 0.2032)
		(layers "F.Cu" "B.Cu")
		(net "GND")
	)
	(via
		(at 79.324454 -341.766906)
		(size 0.49022)
		(drill 0.254)
		(layers "F.Cu" "B.Cu")
		(net "GND")
	)
	(via
		(at 182.549546 -251.716794)
		(size 0.4572)
		(drill 0.2032)
		(layers "F.Cu" "B.Cu")
		(net "GND")
	)
	(via
		(at 191.983614 -216.866724)
		(size 0.4572)
		(drill 0.2032)
		(layers "F.Cu" "B.Cu")
		(net "GND")
	)
	(via
		(at 122.088148 -275.08073)
		(size 0.4572)
		(drill 0.2032)
		(layers "F.Cu" "B.Cu")
		(net "GND")
	)
	(via
		(at 100.002594 -257.98907)
		(size 0.4572)
		(drill 0.2032)
		(layers "F.Cu" "B.Cu")
		(net "GND")
	)
	(via
		(at 232.133902 -115.670584)
		(size 0.508)
		(drill 0.254)
		(layers "F.Cu" "B.Cu")
		(net "GND")
	)
	(via
		(at 271.936972 -72.5424)
		(size 0.508)
		(drill 0.254)
		(layers "F.Cu" "B.Cu")
		(net "GND")
	)
	(via
		(at 171.1325 -19.733768)
		(size 0.508)
		(drill 0.254)
		(layers "F.Cu" "B.Cu")
		(net "GND")
	)
	(via
		(at 412.238444 -205.816708)
		(size 0.4572)
		(drill 0.2032)
		(layers "F.Cu" "B.Cu")
		(net "GND")
	)
	(via
		(at 398.43329 -403.883876)
		(size 0.4064)
		(drill 0.2032)
		(layers "F.Cu" "B.Cu")
		(net "GND")
	)
	(via
		(at 368.50828 -231.714548)
		(size 0.4572)
		(drill 0.2032)
		(layers "F.Cu" "B.Cu")
		(net "GND")
	)
	(via
		(at 184.439814 -294.216582)
		(size 0.4572)
		(drill 0.2032)
		(layers "F.Cu" "B.Cu")
		(net "GND")
	)
	(via
		(at 382.299464 -347.909896)
		(size 0.508)
		(drill 0.254)
		(layers "F.Cu" "B.Cu")
		(net "GND")
	)
	(via
		(at 44.754546 -292.516814)
		(size 0.4572)
		(drill 0.2032)
		(layers "F.Cu" "B.Cu")
		(net "GND")
	)
	(via
		(at 261.285482 -267.866622)
		(size 0.4572)
		(drill 0.2032)
		(layers "F.Cu" "B.Cu")
		(net "GND")
	)
	(via
		(at 33.767014 -244.066568)
		(size 0.4572)
		(drill 0.2032)
		(layers "F.Cu" "B.Cu")
		(net "GND")
	)
	(via
		(at 430.489614 -263.616694)
		(size 0.4572)
		(drill 0.2032)
		(layers "F.Cu" "B.Cu")
		(net "GND")
	)
	(via
		(at 327.140824 -344.965274)
		(size 0.49022)
		(drill 0.254)
		(layers "F.Cu" "B.Cu")
		(net "GND")
	)
	(via
		(at 71.294498 -35.749484)
		(size 0.508)
		(drill 0.254)
		(layers "F.Cu" "B.Cu")
		(net "GND")
	)
	(via
		(at 339.014562 -286.475424)
		(size 0.4572)
		(drill 0.2032)
		(layers "F.Cu" "B.Cu")
		(net "GND")
	)
	(via
		(at 342.773762 -263.686544)
		(size 0.4572)
		(drill 0.2032)
		(layers "F.Cu" "B.Cu")
		(net "GND")
	)
	(via
		(at 259.075682 -200.716642)
		(size 0.4572)
		(drill 0.2032)
		(layers "F.Cu" "B.Cu")
		(net "GND")
	)
	(via
		(at 420.736014 -272.116804)
		(size 0.4572)
		(drill 0.2032)
		(layers "F.Cu" "B.Cu")
		(net "GND")
	)
	(via
		(at 105.641648 -279.150318)
		(size 0.4572)
		(drill 0.2032)
		(layers "F.Cu" "B.Cu")
		(net "GND")
	)
	(via
		(at 56.398414 -289.966654)
		(size 0.4572)
		(drill 0.2032)
		(layers "F.Cu" "B.Cu")
		(net "GND")
	)
	(via
		(at 332.326234 -229.272846)
		(size 0.4572)
		(drill 0.2032)
		(layers "F.Cu" "B.Cu")
		(net "GND")
	)
	(via
		(at 28.433014 -271.266666)
		(size 0.4572)
		(drill 0.2032)
		(layers "F.Cu" "B.Cu")
		(net "GND")
	)
	(via
		(at 86.824566 -335.187036)
		(size 0.49022)
		(drill 0.254)
		(layers "F.Cu" "B.Cu")
		(net "GND")
	)
	(via
		(at 330.252578 -48.920146)
		(size 0.4572)
		(drill 0.2032)
		(layers "F.Cu" "B.Cu")
		(net "GND")
	)
	(via
		(at 334.317848 -410.030168)
		(size 0.4064)
		(drill 0.2032)
		(layers "F.Cu" "B.Cu")
		(net "GND")
	)
	(via
		(at 124.327412 -234.970066)
		(size 0.4572)
		(drill 0.2032)
		(layers "F.Cu" "B.Cu")
		(net "GND")
	)
	(via
		(at 110.230666 -220.319854)
		(size 0.4572)
		(drill 0.2032)
		(layers "F.Cu" "B.Cu")
		(net "GND")
	)
	(via
		(at 340.250018 -438.651396)
		(size 0.4572)
		(drill 0.2032)
		(layers "F.Cu" "B.Cu")
		(net "GND")
	)
	(via
		(at 2.764536 -376.350022)
		(size 0.508)
		(drill 0.254)
		(layers "F.Cu" "B.Cu")
		(net "GND")
	)
	(via
		(at 96.121474 -335.704434)
		(size 0.49022)
		(drill 0.254)
		(layers "F.Cu" "B.Cu")
		(net "GND")
	)
	(via
		(at 39.420546 -231.316784)
		(size 0.4572)
		(drill 0.2032)
		(layers "F.Cu" "B.Cu")
		(net "GND")
	)
	(via
		(at 361.569762 -253.919736)
		(size 0.4572)
		(drill 0.2032)
		(layers "F.Cu" "B.Cu")
		(net "GND")
	)
	(via
		(at 289.250882 -310.366664)
		(size 0.4572)
		(drill 0.2032)
		(layers "F.Cu" "B.Cu")
		(net "GND")
	)
	(via
		(at 336.13598 -336.765392)
		(size 0.49022)
		(drill 0.254)
		(layers "F.Cu" "B.Cu")
		(net "GND")
	)
	(via
		(at 205.180946 -214.316564)
		(size 0.4572)
		(drill 0.2032)
		(layers "F.Cu" "B.Cu")
		(net "GND")
	)
	(via
		(at 75.351386 -404.51786)
		(size 0.4572)
		(drill 0.254)
		(layers "F.Cu" "B.Cu")
		(net "GND")
	)
	(via
		(at 60.551822 -159.56788)
		(size 0.508)
		(drill 0.254)
		(layers "F.Cu" "B.Cu")
		(net "GND")
	)
	(via
		(at 202.971146 -296.766742)
		(size 0.4572)
		(drill 0.2032)
		(layers "F.Cu" "B.Cu")
		(net "GND")
	)
	(via
		(at 182.549546 -250.016772)
		(size 0.4572)
		(drill 0.2032)
		(layers "F.Cu" "B.Cu")
		(net "GND")
	)
	(via
		(at 307.782214 -279.766776)
		(size 0.4572)
		(drill 0.2032)
		(layers "F.Cu" "B.Cu")
		(net "GND")
	)
	(via
		(at 151.848566 -400.224244)
		(size 0.4572)
		(drill 0.254)
		(layers "F.Cu" "B.Cu")
		(net "GND")
	)
	(via
		(at 133.469126 -404.51786)
		(size 0.4572)
		(drill 0.254)
		(layers "F.Cu" "B.Cu")
		(net "GND")
	)
	(via
		(at 385.099052 -342.556084)
		(size 0.49022)
		(drill 0.254)
		(layers "F.Cu" "B.Cu")
		(net "GND")
	)
	(via
		(at 344.073734 -226.831144)
		(size 0.4572)
		(drill 0.2032)
		(layers "F.Cu" "B.Cu")
		(net "GND")
	)
	(via
		(at 144.102074 -403.883876)
		(size 0.4064)
		(drill 0.2032)
		(layers "F.Cu" "B.Cu")
		(net "GND")
	)
	(via
		(at 338.544662 -280.778204)
		(size 0.4572)
		(drill 0.2032)
		(layers "F.Cu" "B.Cu")
		(net "GND")
	)
	(via
		(at 443.367414 -236.416596)
		(size 0.4572)
		(drill 0.2032)
		(layers "F.Cu" "B.Cu")
		(net "GND")
	)
	(via
		(at 311.882282 -200.716642)
		(size 0.4572)
		(drill 0.2032)
		(layers "F.Cu" "B.Cu")
		(net "GND")
	)
	(via
		(at 272.273014 -227.066602)
		(size 0.4572)
		(drill 0.2032)
		(layers "F.Cu" "B.Cu")
		(net "GND")
	)
	(via
		(at 350.774762 -250.550934)
		(size 0.4572)
		(drill 0.2032)
		(layers "F.Cu" "B.Cu")
		(net "GND")
	)
	(via
		(at 40.212772 -352.397822)
		(size 0.49022)
		(drill 0.254)
		(layers "F.Cu" "B.Cu")
		(net "GND")
	)
	(via
		(at 382.135634 -226.017328)
		(size 0.4572)
		(drill 0.2032)
		(layers "F.Cu" "B.Cu")
		(net "GND")
	)
	(via
		(at 356.761034 -234.15625)
		(size 0.4572)
		(drill 0.2032)
		(layers "F.Cu" "B.Cu")
		(net "GND")
	)
	(via
		(at 453.121014 -212.616796)
		(size 0.4572)
		(drill 0.2032)
		(layers "F.Cu" "B.Cu")
		(net "GND")
	)
	(via
		(at 92.95638 -112.944148)
		(size 0.508)
		(drill 0.254)
		(layers "F.Cu" "B.Cu")
		(net "GND")
	)
	(via
		(at 165.646862 -24.91867)
		(size 0.508)
		(drill 0.254)
		(layers "F.Cu" "B.Cu")
		(net "GND")
	)
	(via
		(at 311.666382 -219.41663)
		(size 0.4572)
		(drill 0.2032)
		(layers "F.Cu" "B.Cu")
		(net "GND")
	)
	(via
		(at 7.035546 -317.166752)
		(size 0.4572)
		(drill 0.2032)
		(layers "F.Cu" "B.Cu")
		(net "GND")
	)
	(via
		(at 408.11831 -301.866808)
		(size 0.4572)
		(drill 0.2032)
		(layers "F.Cu" "B.Cu")
		(net "GND")
	)
	(via
		(at 106.111294 -266.941808)
		(size 0.4572)
		(drill 0.2032)
		(layers "F.Cu" "B.Cu")
		(net "GND")
	)
	(via
		(at 334.899508 -44.849796)
		(size 0.4572)
		(drill 0.2032)
		(layers "F.Cu" "B.Cu")
		(net "GND")
	)
	(via
		(at 337.49488 -238.225584)
		(size 0.4572)
		(drill 0.2032)
		(layers "F.Cu" "B.Cu")
		(net "GND")
	)
	(via
		(at 107.051348 -275.08073)
		(size 0.4572)
		(drill 0.2032)
		(layers "F.Cu" "B.Cu")
		(net "GND")
	)
	(via
		(at 415.402014 -242.3668)
		(size 0.4572)
		(drill 0.2032)
		(layers "F.Cu" "B.Cu")
		(net "GND")
	)
	(via
		(at 82.250026 -426.54728)
		(size 0.4572)
		(drill 0.2032)
		(layers "F.Cu" "B.Cu")
		(net "GND")
	)
	(via
		(at 118.781576 -339.339174)
		(size 0.508)
		(drill 0.254)
		(layers "F.Cu" "B.Cu")
		(net "GND")
	)
	(via
		(at 417.289742 -154.992324)
		(size 0.508)
		(drill 0.254)
		(layers "F.Cu" "B.Cu")
		(net "GND")
	)
	(via
		(at 294.904414 -265.316716)
		(size 0.4572)
		(drill 0.2032)
		(layers "F.Cu" "B.Cu")
		(net "GND")
	)
	(via
		(at 341.918798 -42.811446)
		(size 0.4572)
		(drill 0.2032)
		(layers "F.Cu" "B.Cu")
		(net "GND")
	)
	(via
		(at 31.876746 -304.416714)
		(size 0.4572)
		(drill 0.2032)
		(layers "F.Cu" "B.Cu")
		(net "GND")
	)
	(via
		(at 131.015994 -266.128246)
		(size 0.4572)
		(drill 0.2032)
		(layers "F.Cu" "B.Cu")
		(net "GND")
	)
	(via
		(at 24.332946 -251.716794)
		(size 0.4572)
		(drill 0.2032)
		(layers "F.Cu" "B.Cu")
		(net "GND")
	)
	(via
		(at 367.098834 -227.64496)
		(size 0.4572)
		(drill 0.2032)
		(layers "F.Cu" "B.Cu")
		(net "GND")
	)
	(via
		(at 398.336262 -410.664152)
		(size 0.4572)
		(drill 0.254)
		(layers "F.Cu" "B.Cu")
		(net "GND")
	)
	(via
		(at 443.367414 -315.46673)
		(size 0.4572)
		(drill 0.2032)
		(layers "F.Cu" "B.Cu")
		(net "GND")
	)
	(via
		(at 180.339746 -233.016806)
		(size 0.4572)
		(drill 0.2032)
		(layers "F.Cu" "B.Cu")
		(net "GND")
	)
	(via
		(at 257.185414 -244.916706)
		(size 0.4572)
		(drill 0.2032)
		(layers "F.Cu" "B.Cu")
		(net "GND")
	)
	(via
		(at 333.944214 -17.437608)
		(size 0.508)
		(drill 0.254)
		(layers "F.Cu" "B.Cu")
		(net "GND")
	)
	(via
		(at 432.379882 -280.61666)
		(size 0.4572)
		(drill 0.2032)
		(layers "F.Cu" "B.Cu")
		(net "GND")
	)
	(via
		(at 41.310814 -247.466612)
		(size 0.4572)
		(drill 0.2032)
		(layers "F.Cu" "B.Cu")
		(net "GND")
	)
	(via
		(at 342.908128 -86.261194)
		(size 0.508)
		(drill 0.254)
		(layers "F.Cu" "B.Cu")
		(net "GND")
	)
	(via
		(at 46.964346 -315.46673)
		(size 0.4572)
		(drill 0.2032)
		(layers "F.Cu" "B.Cu")
		(net "GND")
	)
	(via
		(at 179.105814 -297.616626)
		(size 0.4572)
		(drill 0.2032)
		(layers "F.Cu" "B.Cu")
		(net "GND")
	)
	(via
		(at 54.819296 -345.744546)
		(size 0.508)
		(drill 0.254)
		(layers "F.Cu" "B.Cu")
		(net "GND")
	)
	(via
		(at 420.567866 -358.754172)
		(size 0.508)
		(drill 0.254)
		(layers "F.Cu" "B.Cu")
		(net "GND")
	)
	(via
		(at 382.245616 -281.59202)
		(size 0.4572)
		(drill 0.2032)
		(layers "F.Cu" "B.Cu")
		(net "GND")
	)
	(via
		(at 156.25699 -17.655032)
		(size 0.508)
		(drill 0.254)
		(layers "F.Cu" "B.Cu")
		(net "GND")
	)
	(via
		(at 370.968016 -266.941808)
		(size 0.4572)
		(drill 0.2032)
		(layers "F.Cu" "B.Cu")
		(net "GND")
	)
	(via
		(at 107.881166 -229.272846)
		(size 0.4572)
		(drill 0.2032)
		(layers "F.Cu" "B.Cu")
		(net "GND")
	)
	(via
		(at 426.595032 -386.821934)
		(size 0.508)
		(drill 0.254)
		(layers "F.Cu" "B.Cu")
		(net "GND")
	)
	(via
		(at 355.461062 -284.033722)
		(size 0.4572)
		(drill 0.2032)
		(layers "F.Cu" "B.Cu")
		(net "GND")
	)
	(via
		(at 396.349982 -431.29962)
		(size 0.4572)
		(drill 0.2032)
		(layers "F.Cu" "B.Cu")
		(net "GND")
	)
	(via
		(at 127.616966 -237.411514)
		(size 0.4572)
		(drill 0.2032)
		(layers "F.Cu" "B.Cu")
		(net "GND")
	)
	(via
		(at 330.966318 -199.602598)
		(size 0.508)
		(drill 0.254)
		(layers "F.Cu" "B.Cu")
		(net "GND")
	)
	(via
		(at 286.773366 -360.83621)
		(size 0.49022)
		(drill 0.254)
		(layers "F.Cu" "B.Cu")
		(net "GND")
	)
	(via
		(at 37.977572 -132.79374)
		(size 0.508)
		(drill 0.254)
		(layers "F.Cu" "B.Cu")
		(net "GND")
	)
	(via
		(at 351.351088 -400.858228)
		(size 0.4064)
		(drill 0.2032)
		(layers "F.Cu" "B.Cu")
		(net "GND")
	)
	(via
		(at 50.38725 -409.396184)
		(size 0.4572)
		(drill 0.254)
		(layers "F.Cu" "B.Cu")
		(net "GND")
	)
	(via
		(at 279.816814 -296.766742)
		(size 0.4572)
		(drill 0.2032)
		(layers "F.Cu" "B.Cu")
		(net "GND")
	)
	(via
		(at 132.315966 -226.017328)
		(size 0.4572)
		(drill 0.2032)
		(layers "F.Cu" "B.Cu")
		(net "GND")
	)
	(via
		(at 62.051946 -204.96657)
		(size 0.4572)
		(drill 0.2032)
		(layers "F.Cu" "B.Cu")
		(net "GND")
	)
	(via
		(at 127.726948 -268.569694)
		(size 0.4572)
		(drill 0.2032)
		(layers "F.Cu" "B.Cu")
		(net "GND")
	)
	(via
		(at 195.427346 -248.31675)
		(size 0.4572)
		(drill 0.2032)
		(layers "F.Cu" "B.Cu")
		(net "GND")
	)
	(via
		(at 382.245616 -258.80314)
		(size 0.4572)
		(drill 0.2032)
		(layers "F.Cu" "B.Cu")
		(net "GND")
	)
	(via
		(at 26.223214 -303.566576)
		(size 0.4572)
		(drill 0.2032)
		(layers "F.Cu" "B.Cu")
		(net "GND")
	)
	(via
		(at 174.213774 -352.408236)
		(size 0.49022)
		(drill 0.254)
		(layers "F.Cu" "B.Cu")
		(net "GND")
	)
	(via
		(at 35.976814 -226.216718)
		(size 0.4572)
		(drill 0.2032)
		(layers "F.Cu" "B.Cu")
		(net "GND")
	)
	(via
		(at 190.093346 -313.766708)
		(size 0.4572)
		(drill 0.2032)
		(layers "F.Cu" "B.Cu")
		(net "GND")
	)
	(via
		(at 24.332946 -260.21665)
		(size 0.4572)
		(drill 0.2032)
		(layers "F.Cu" "B.Cu")
		(net "GND")
	)
	(via
		(at 7.035546 -300.166786)
		(size 0.4572)
		(drill 0.2032)
		(layers "F.Cu" "B.Cu")
		(net "GND")
	)
	(via
		(at 407.34996 -430.299622)
		(size 0.4572)
		(drill 0.2032)
		(layers "F.Cu" "B.Cu")
		(net "GND")
	)
	(via
		(at 143.34998 -425.547282)
		(size 0.4572)
		(drill 0.2032)
		(layers "F.Cu" "B.Cu")
		(net "GND")
	)
	(via
		(at 349.352362 -268.569694)
		(size 0.4572)
		(drill 0.2032)
		(layers "F.Cu" "B.Cu")
		(net "GND")
	)
	(via
		(at 129.255774 -356.83952)
		(size 0.508)
		(drill 0.254)
		(layers "F.Cu" "B.Cu")
		(net "GND")
	)
	(via
		(at 166.026084 -323.434456)
		(size 0.4572)
		(drill 0.2032)
		(layers "F.Cu" "B.Cu")
		(net "GND")
	)
	(via
		(at 300.238414 -250.016772)
		(size 0.4572)
		(drill 0.2032)
		(layers "F.Cu" "B.Cu")
		(net "GND")
	)
	(via
		(at 385.09829 -400.858228)
		(size 0.4064)
		(drill 0.2032)
		(layers "F.Cu" "B.Cu")
		(net "GND")
	)
	(via
		(at 213.051136 -99.79152)
		(size 0.508)
		(drill 0.254)
		(layers "F.Cu" "B.Cu")
		(net "GND")
	)
	(via
		(at 341.887556 -407.638504)
		(size 0.4572)
		(drill 0.254)
		(layers "F.Cu" "B.Cu")
		(net "GND")
	)
	(via
		(at 281.707082 -282.316682)
		(size 0.4572)
		(drill 0.2032)
		(layers "F.Cu" "B.Cu")
		(net "GND")
	)
	(via
		(at 35.586416 -396.274544)
		(size 0.508)
		(drill 0.254)
		(layers "F.Cu" "B.Cu")
		(net "GND")
	)
	(via
		(at 330.8223 -73.678288)
		(size 0.508)
		(drill 0.254)
		(layers "F.Cu" "B.Cu")
		(net "GND")
	)
	(via
		(at 427.510194 -5.585714)
		(size 0.508)
		(drill 0.254)
		(layers "F.Cu" "B.Cu")
		(net "GND")
	)
	(via
		(at 272.273014 -244.916706)
		(size 0.4572)
		(drill 0.2032)
		(layers "F.Cu" "B.Cu")
		(net "GND")
	)
	(via
		(at 186.649614 -222.816674)
		(size 0.4572)
		(drill 0.2032)
		(layers "F.Cu" "B.Cu")
		(net "GND")
	)
	(via
		(at 29.22524 -139.066524)
		(size 0.508)
		(drill 0.254)
		(layers "F.Cu" "B.Cu")
		(net "GND")
	)
	(via
		(at 135.605266 -226.831144)
		(size 0.4572)
		(drill 0.2032)
		(layers "F.Cu" "B.Cu")
		(net "GND")
	)
	(via
		(at 9.245346 -227.066602)
		(size 0.4572)
		(drill 0.2032)
		(layers "F.Cu" "B.Cu")
		(net "GND")
	)
	(via
		(at 127.726948 -276.708616)
		(size 0.4572)
		(drill 0.2032)
		(layers "F.Cu" "B.Cu")
		(net "GND")
	)
	(via
		(at 130.906266 -217.064336)
		(size 0.4572)
		(drill 0.2032)
		(layers "F.Cu" "B.Cu")
		(net "GND")
	)
	(via
		(at 403.203918 -410.664152)
		(size 0.4572)
		(drill 0.254)
		(layers "F.Cu" "B.Cu")
		(net "GND")
	)
	(via
		(at 420.567866 -360.074972)
		(size 0.508)
		(drill 0.254)
		(layers "F.Cu" "B.Cu")
		(net "GND")
	)
	(via
		(at 94.723966 -240.667286)
		(size 0.4572)
		(drill 0.2032)
		(layers "F.Cu" "B.Cu")
		(net "GND")
	)
	(via
		(at 123.497594 -284.033722)
		(size 0.4572)
		(drill 0.2032)
		(layers "F.Cu" "B.Cu")
		(net "GND")
	)
	(via
		(at 333.117444 -278.711406)
		(size 0.4572)
		(drill 0.2032)
		(layers "F.Cu" "B.Cu")
		(net "GND")
	)
	(via
		(at 149.146514 -400.858228)
		(size 0.4064)
		(drill 0.2032)
		(layers "F.Cu" "B.Cu")
		(net "GND")
	)
	(via
		(at 261.285482 -266.1666)
		(size 0.4572)
		(drill 0.2032)
		(layers "F.Cu" "B.Cu")
		(net "GND")
	)
	(via
		(at 466.85708 -116.616734)
		(size 0.508)
		(drill 0.254)
		(layers "F.Cu" "B.Cu")
		(net "GND")
	)
	(via
		(at 352.24212 -50.207672)
		(size 0.49022)
		(drill 0.254)
		(layers "F.Cu" "B.Cu")
		(net "GND")
	)
	(via
		(at 130.717798 -362.29163)
		(size 0.6604)
		(drill 0.3302)
		(layers "F.Cu" "B.Cu")
		(net "GND")
	)
	(via
		(at 350.9899 -401.492212)
		(size 0.4572)
		(drill 0.254)
		(layers "F.Cu" "B.Cu")
		(net "GND")
	)
	(via
		(at 353.001834 -229.272846)
		(size 0.4572)
		(drill 0.2032)
		(layers "F.Cu" "B.Cu")
		(net "GND")
	)
	(via
		(at 84.20481 -338.964016)
		(size 0.508)
		(drill 0.254)
		(layers "F.Cu" "B.Cu")
		(net "GND")
	)
	(via
		(at 272.273014 -214.316564)
		(size 0.4572)
		(drill 0.2032)
		(layers "F.Cu" "B.Cu")
		(net "GND")
	)
	(via
		(at 103.182166 -219.506038)
		(size 0.4572)
		(drill 0.2032)
		(layers "F.Cu" "B.Cu")
		(net "GND")
	)
	(via
		(at 270.063214 -208.366614)
		(size 0.4572)
		(drill 0.2032)
		(layers "F.Cu" "B.Cu")
		(net "GND")
	)
	(via
		(at 405.648414 -263.616694)
		(size 0.4572)
		(drill 0.2032)
		(layers "F.Cu" "B.Cu")
		(net "GND")
	)
	(via
		(at 136.893554 -400.858228)
		(size 0.4064)
		(drill 0.2032)
		(layers "F.Cu" "B.Cu")
		(net "GND")
	)
	(via
		(at 118.218966 -232.528364)
		(size 0.4572)
		(drill 0.2032)
		(layers "F.Cu" "B.Cu")
		(net "GND")
	)
	(via
		(at 69.250052 -431.29962)
		(size 0.4572)
		(drill 0.2032)
		(layers "F.Cu" "B.Cu")
		(net "GND")
	)
	(via
		(at 122.558048 -262.872474)
		(size 0.4572)
		(drill 0.2032)
		(layers "F.Cu" "B.Cu")
		(net "GND")
	)
	(via
		(at 65.25006 -437.34736)
		(size 0.4572)
		(drill 0.2032)
		(layers "F.Cu" "B.Cu")
		(net "GND")
	)
	(via
		(at 456.460352 -323.429376)
		(size 0.4572)
		(drill 0.2032)
		(layers "F.Cu" "B.Cu")
		(net "GND")
	)
	(via
		(at 129.147062 -400.224244)
		(size 0.4572)
		(drill 0.254)
		(layers "F.Cu" "B.Cu")
		(net "GND")
	)
	(via
		(at 158.9532 -79.225648)
		(size 0.508)
		(drill 0.254)
		(layers "F.Cu" "B.Cu")
		(net "GND")
	)
	(via
		(at 89.554812 -233.34218)
		(size 0.4572)
		(drill 0.2032)
		(layers "F.Cu" "B.Cu")
		(net "GND")
	)
	(via
		(at 291.113972 -354.870004)
		(size 0.508)
		(drill 0.254)
		(layers "F.Cu" "B.Cu")
		(net "GND")
	)
	(via
		(at 7.035546 -216.016586)
		(size 0.4572)
		(drill 0.2032)
		(layers "F.Cu" "B.Cu")
		(net "GND")
	)
	(via
		(at 55.211218 -170.689524)
		(size 0.508)
		(drill 0.254)
		(layers "F.Cu" "B.Cu")
		(net "GND")
	)
	(via
		(at 259.075682 -288.266632)
		(size 0.4572)
		(drill 0.2032)
		(layers "F.Cu" "B.Cu")
		(net "GND")
	)
	(via
		(at 415.402014 -283.166566)
		(size 0.4572)
		(drill 0.2032)
		(layers "F.Cu" "B.Cu")
		(net "GND")
	)
	(via
		(at 350.835722 -252.798834)
		(size 0.4572)
		(drill 0.2032)
		(layers "F.Cu" "B.Cu")
		(net "GND")
	)
	(via
		(at 195.427346 -244.916706)
		(size 0.4572)
		(drill 0.2032)
		(layers "F.Cu" "B.Cu")
		(net "GND")
	)
	(via
		(at 35.976814 -269.566644)
		(size 0.4572)
		(drill 0.2032)
		(layers "F.Cu" "B.Cu")
		(net "GND")
	)
	(via
		(at 191.983614 -233.86669)
		(size 0.4572)
		(drill 0.2032)
		(layers "F.Cu" "B.Cu")
		(net "GND")
	)
	(via
		(at 312.4835 -22.7203)
		(size 0.508)
		(drill 0.254)
		(layers "F.Cu" "B.Cu")
		(net "GND")
	)
	(via
		(at 449.677282 -226.216718)
		(size 0.4572)
		(drill 0.2032)
		(layers "F.Cu" "B.Cu")
		(net "GND")
	)
	(via
		(at 171.562014 -286.56661)
		(size 0.4572)
		(drill 0.2032)
		(layers "F.Cu" "B.Cu")
		(net "GND")
	)
	(via
		(at 75.254358 -407.00452)
		(size 0.4064)
		(drill 0.2032)
		(layers "F.Cu" "B.Cu")
		(net "GND")
	)
	(via
		(at 165.252146 -289.11677)
		(size 0.4572)
		(drill 0.2032)
		(layers "F.Cu" "B.Cu")
		(net "GND")
	)
	(via
		(at 100.525834 -329.10272)
		(size 0.508)
		(drill 0.254)
		(layers "F.Cu" "B.Cu")
		(net "GND")
	)
	(via
		(at 292.314122 -359.442004)
		(size 0.508)
		(drill 0.254)
		(layers "F.Cu" "B.Cu")
		(net "GND")
	)
	(via
		(at 321.587622 -33.010348)
		(size 0.508)
		(drill 0.254)
		(layers "F.Cu" "B.Cu")
		(net "GND")
	)
	(via
		(at 404.82393 -410.030168)
		(size 0.4064)
		(drill 0.2032)
		(layers "F.Cu" "B.Cu")
		(net "GND")
	)
	(via
		(at 294.904414 -317.166752)
		(size 0.4572)
		(drill 0.2032)
		(layers "F.Cu" "B.Cu")
		(net "GND")
	)
	(via
		(at 109.06633 -60.086748)
		(size 0.508)
		(drill 0.254)
		(layers "F.Cu" "B.Cu")
		(net "GND")
	)
	(via
		(at 22.23008 -98.171508)
		(size 0.508)
		(drill 0.254)
		(layers "F.Cu" "B.Cu")
		(net "GND")
	)
	(via
		(at 7.035546 -212.616796)
		(size 0.4572)
		(drill 0.2032)
		(layers "F.Cu" "B.Cu")
		(net "GND")
	)
	(via
		(at 135.605266 -233.34218)
		(size 0.4572)
		(drill 0.2032)
		(layers "F.Cu" "B.Cu")
		(net "GND")
	)
	(via
		(at 155.349956 -437.49976)
		(size 0.4572)
		(drill 0.2032)
		(layers "F.Cu" "B.Cu")
		(net "GND")
	)
	(via
		(at 16.789146 -214.316564)
		(size 0.4572)
		(drill 0.2032)
		(layers "F.Cu" "B.Cu")
		(net "GND")
	)
	(via
		(at 377.021344 -366.329214)
		(size 0.508)
		(drill 0.254)
		(layers "F.Cu" "B.Cu")
		(net "GND")
	)
	(via
		(at 156.258006 -410.664152)
		(size 0.4572)
		(drill 0.254)
		(layers "F.Cu" "B.Cu")
		(net "GND")
	)
	(via
		(at 311.666382 -238.116618)
		(size 0.4572)
		(drill 0.2032)
		(layers "F.Cu" "B.Cu")
		(net "GND")
	)
	(via
		(at 373.207534 -220.319854)
		(size 0.4572)
		(drill 0.2032)
		(layers "F.Cu" "B.Cu")
		(net "GND")
	)
	(via
		(at 410.35732 -176.367948)
		(size 0.508)
		(drill 0.254)
		(layers "F.Cu" "B.Cu")
		(net "GND")
	)
	(via
		(at 58.811414 -235.566712)
		(size 0.4572)
		(drill 0.2032)
		(layers "F.Cu" "B.Cu")
		(net "GND")
	)
	(via
		(at 427.045882 -228.766624)
		(size 0.4572)
		(drill 0.2032)
		(layers "F.Cu" "B.Cu")
		(net "GND")
	)
	(via
		(at 434.589682 -235.566712)
		(size 0.4572)
		(drill 0.2032)
		(layers "F.Cu" "B.Cu")
		(net "GND")
	)
	(via
		(at 377.43638 -248.806208)
		(size 0.4572)
		(drill 0.2032)
		(layers "F.Cu" "B.Cu")
		(net "GND")
	)
	(via
		(at 428.279814 -225.36658)
		(size 0.4572)
		(drill 0.2032)
		(layers "F.Cu" "B.Cu")
		(net "GND")
	)
	(via
		(at 302.448214 -242.3668)
		(size 0.4572)
		(drill 0.2032)
		(layers "F.Cu" "B.Cu")
		(net "GND")
	)
	(via
		(at 184.580276 -350.922082)
		(size 0.508)
		(drill 0.254)
		(layers "F.Cu" "B.Cu")
		(net "GND")
	)
	(via
		(at 28.433014 -247.466612)
		(size 0.4572)
		(drill 0.2032)
		(layers "F.Cu" "B.Cu")
		(net "GND")
	)
	(via
		(at 341.834216 -260.430772)
		(size 0.4572)
		(drill 0.2032)
		(layers "F.Cu" "B.Cu")
		(net "GND")
	)
	(via
		(at 453.121014 -227.066602)
		(size 0.4572)
		(drill 0.2032)
		(layers "F.Cu" "B.Cu")
		(net "GND")
	)
	(via
		(at 179.105814 -202.416664)
		(size 0.4572)
		(drill 0.2032)
		(layers "F.Cu" "B.Cu")
		(net "GND")
	)
	(via
		(at 69.224906 -401.492212)
		(size 0.4572)
		(drill 0.254)
		(layers "F.Cu" "B.Cu")
		(net "GND")
	)
	(via
		(at 63.942214 -278.916638)
		(size 0.4572)
		(drill 0.2032)
		(layers "F.Cu" "B.Cu")
		(net "GND")
	)
	(via
		(at 361.569762 -257.175254)
		(size 0.4572)
		(drill 0.2032)
		(layers "F.Cu" "B.Cu")
		(net "GND")
	)
	(via
		(at 368.038634 -222.761556)
		(size 0.4572)
		(drill 0.2032)
		(layers "F.Cu" "B.Cu")
		(net "GND")
	)
	(via
		(at 467.535514 -393.56538)
		(size 0.508)
		(drill 0.254)
		(layers "F.Cu" "B.Cu")
		(net "GND")
	)
	(via
		(at 348.882462 -274.266914)
		(size 0.4572)
		(drill 0.2032)
		(layers "F.Cu" "B.Cu")
		(net "GND")
	)
	(via
		(at 415.648648 -162.826954)
		(size 0.49022)
		(drill 0.254)
		(layers "F.Cu" "B.Cu")
		(net "GND")
	)
	(via
		(at 274.163282 -222.816674)
		(size 0.4572)
		(drill 0.2032)
		(layers "F.Cu" "B.Cu")
		(net "GND")
	)
	(via
		(at 56.182514 -207.51673)
		(size 0.4572)
		(drill 0.2032)
		(layers "F.Cu" "B.Cu")
		(net "GND")
	)
	(via
		(at 451.923404 -70.003416)
		(size 0.508)
		(drill 0.254)
		(layers "F.Cu" "B.Cu")
		(net "GND")
	)
	(via
		(at 180.339746 -290.816792)
		(size 0.4572)
		(drill 0.2032)
		(layers "F.Cu" "B.Cu")
		(net "GND")
	)
	(via
		(at 413.192214 -309.51678)
		(size 0.4572)
		(drill 0.2032)
		(layers "F.Cu" "B.Cu")
		(net "GND")
	)
	(via
		(at 219.73413 -12.544552)
		(size 0.508)
		(drill 0.254)
		(layers "F.Cu" "B.Cu")
		(net "GND")
	)
	(via
		(at 409.748482 -247.466612)
		(size 0.4572)
		(drill 0.2032)
		(layers "F.Cu" "B.Cu")
		(net "GND")
	)
	(via
		(at 35.176968 -436.268368)
		(size 0.508)
		(drill 0.254)
		(layers "F.Cu" "B.Cu")
		(net "GND")
	)
	(via
		(at 396.349982 -430.147222)
		(size 0.4572)
		(drill 0.2032)
		(layers "F.Cu" "B.Cu")
		(net "GND")
	)
	(via
		(at 272.273014 -265.316716)
		(size 0.4572)
		(drill 0.2032)
		(layers "F.Cu" "B.Cu")
		(net "GND")
	)
	(via
		(at 306.548282 -301.01667)
		(size 0.4572)
		(drill 0.2032)
		(layers "F.Cu" "B.Cu")
		(net "GND")
	)
	(via
		(at 429.992282 -178.801522)
		(size 0.508)
		(drill 0.254)
		(layers "F.Cu" "B.Cu")
		(net "GND")
	)
	(via
		(at 42.357294 -440.173618)
		(size 0.508)
		(drill 0.254)
		(layers "F.Cu" "B.Cu")
		(net "GND")
	)
	(via
		(at 347.002862 -280.778204)
		(size 0.4572)
		(drill 0.2032)
		(layers "F.Cu" "B.Cu")
		(net "GND")
	)
	(via
		(at 16.789146 -270.416782)
		(size 0.4572)
		(drill 0.2032)
		(layers "F.Cu" "B.Cu")
		(net "GND")
	)
	(via
		(at 63.942214 -291.666676)
		(size 0.4572)
		(drill 0.2032)
		(layers "F.Cu" "B.Cu")
		(net "GND")
	)
	(via
		(at 201.737214 -247.466612)
		(size 0.4572)
		(drill 0.2032)
		(layers "F.Cu" "B.Cu")
		(net "GND")
	)
	(via
		(at 415.799524 -156.610304)
		(size 0.508)
		(drill 0.254)
		(layers "F.Cu" "B.Cu")
		(net "GND")
	)
	(via
		(at 376.496834 -219.506038)
		(size 0.4572)
		(drill 0.2032)
		(layers "F.Cu" "B.Cu")
		(net "GND")
	)
	(via
		(at 212.209634 -92.202762)
		(size 0.508)
		(drill 0.254)
		(layers "F.Cu" "B.Cu")
		(net "GND")
	)
	(via
		(at 413.192214 -315.46673)
		(size 0.4572)
		(drill 0.2032)
		(layers "F.Cu" "B.Cu")
		(net "GND")
	)
	(via
		(at 409.748482 -267.866622)
		(size 0.4572)
		(drill 0.2032)
		(layers "F.Cu" "B.Cu")
		(net "GND")
	)
	(via
		(at 18.679414 -213.46668)
		(size 0.4572)
		(drill 0.2032)
		(layers "F.Cu" "B.Cu")
		(net "GND")
	)
	(via
		(at 150.228554 -403.883876)
		(size 0.4064)
		(drill 0.2032)
		(layers "F.Cu" "B.Cu")
		(net "GND")
	)
	(via
		(at 40.873172 -351.608644)
		(size 0.49022)
		(drill 0.254)
		(layers "F.Cu" "B.Cu")
		(net "GND")
	)
	(via
		(at 309.992014 -251.716794)
		(size 0.4572)
		(drill 0.2032)
		(layers "F.Cu" "B.Cu")
		(net "GND")
	)
	(via
		(at 407.858214 -287.416748)
		(size 0.4572)
		(drill 0.2032)
		(layers "F.Cu" "B.Cu")
		(net "GND")
	)
	(via
		(at 371.672358 -103.237284)
		(size 0.508)
		(drill 0.254)
		(layers "F.Cu" "B.Cu")
		(net "GND")
	)
	(via
		(at 202.971146 -311.216802)
		(size 0.4572)
		(drill 0.2032)
		(layers "F.Cu" "B.Cu")
		(net "GND")
	)
	(via
		(at 339.484716 -254.733552)
		(size 0.4572)
		(drill 0.2032)
		(layers "F.Cu" "B.Cu")
		(net "GND")
	)
	(via
		(at 62.267846 -217.716608)
		(size 0.4572)
		(drill 0.2032)
		(layers "F.Cu" "B.Cu")
		(net "GND")
	)
	(via
		(at 409.349956 -430.147222)
		(size 0.4572)
		(drill 0.2032)
		(layers "F.Cu" "B.Cu")
		(net "GND")
	)
	(via
		(at 333.845662 -264.50036)
		(size 0.4318)
		(drill 0.2032)
		(layers "F.Cu" "B.Cu")
		(net "GND")
	)
	(via
		(at 90.570558 -410.030168)
		(size 0.4064)
		(drill 0.2032)
		(layers "F.Cu" "B.Cu")
		(net "GND")
	)
	(via
		(at 37.210746 -279.766776)
		(size 0.4572)
		(drill 0.2032)
		(layers "F.Cu" "B.Cu")
		(net "GND")
	)
	(via
		(at 424.166792 -12.37488)
		(size 0.508)
		(drill 0.254)
		(layers "F.Cu" "B.Cu")
		(net "GND")
	)
	(via
		(at 285.150814 -238.966756)
		(size 0.4572)
		(drill 0.2032)
		(layers "F.Cu" "B.Cu")
		(net "GND")
	)
	(via
		(at 182.549546 -287.416748)
		(size 0.4572)
		(drill 0.2032)
		(layers "F.Cu" "B.Cu")
		(net "GND")
	)
	(via
		(at 55.41645 -350.915732)
		(size 0.508)
		(drill 0.254)
		(layers "F.Cu" "B.Cu")
		(net "GND")
	)
	(via
		(at 0.76454 -51.640232)
		(size 0.508)
		(drill 0.254)
		(layers "F.Cu" "B.Cu")
		(net "GND")
	)
	(via
		(at 194.193414 -232.166668)
		(size 0.4572)
		(drill 0.2032)
		(layers "F.Cu" "B.Cu")
		(net "GND")
	)
	(via
		(at 261.285482 -305.266598)
		(size 0.4572)
		(drill 0.2032)
		(layers "F.Cu" "B.Cu")
		(net "GND")
	)
	(via
		(at 54.508146 -244.916706)
		(size 0.4572)
		(drill 0.2032)
		(layers "F.Cu" "B.Cu")
		(net "GND")
	)
	(via
		(at 137.108438 -340.977728)
		(size 0.49022)
		(drill 0.254)
		(layers "F.Cu" "B.Cu")
		(net "GND")
	)
	(via
		(at 28.433014 -288.266632)
		(size 0.4572)
		(drill 0.2032)
		(layers "F.Cu" "B.Cu")
		(net "GND")
	)
	(via
		(at 287.360614 -195.616576)
		(size 0.4572)
		(drill 0.2032)
		(layers "F.Cu" "B.Cu")
		(net "GND")
	)
	(via
		(at 339.644736 -332.512924)
		(size 0.508)
		(drill 0.254)
		(layers "F.Cu" "B.Cu")
		(net "GND")
	)
	(via
		(at 297.60037 -363.337094)
		(size 0.49022)
		(drill 0.254)
		(layers "F.Cu" "B.Cu")
		(net "GND")
	)
	(via
		(at 314.307982 -207.51673)
		(size 0.4572)
		(drill 0.2032)
		(layers "F.Cu" "B.Cu")
		(net "GND")
	)
	(via
		(at 65.70345 -406.370536)
		(size 0.4572)
		(drill 0.254)
		(layers "F.Cu" "B.Cu")
		(net "GND")
	)
	(via
		(at 422.945814 -289.11677)
		(size 0.4572)
		(drill 0.2032)
		(layers "F.Cu" "B.Cu")
		(net "GND")
	)
	(via
		(at 363.919262 -267.755878)
		(size 0.4572)
		(drill 0.2032)
		(layers "F.Cu" "B.Cu")
		(net "GND")
	)
	(via
		(at 428.279814 -216.016586)
		(size 0.4572)
		(drill 0.2032)
		(layers "F.Cu" "B.Cu")
		(net "GND")
	)
	(via
		(at 136.184894 -279.964134)
		(size 0.4572)
		(drill 0.2032)
		(layers "F.Cu" "B.Cu")
		(net "GND")
	)
	(via
		(at 264.729214 -223.666558)
		(size 0.4572)
		(drill 0.2032)
		(layers "F.Cu" "B.Cu")
		(net "GND")
	)
	(via
		(at 302.448214 -263.616694)
		(size 0.4572)
		(drill 0.2032)
		(layers "F.Cu" "B.Cu")
		(net "GND")
	)
	(via
		(at 415.402014 -295.06672)
		(size 0.4572)
		(drill 0.2032)
		(layers "F.Cu" "B.Cu")
		(net "GND")
	)
	(via
		(at 334.205834 -248.806208)
		(size 0.4572)
		(drill 0.2032)
		(layers "F.Cu" "B.Cu")
		(net "GND")
	)
	(via
		(at 124.327412 -246.364506)
		(size 0.4572)
		(drill 0.2032)
		(layers "F.Cu" "B.Cu")
		(net "GND")
	)
	(via
		(at 205.180946 -244.916706)
		(size 0.4572)
		(drill 0.2032)
		(layers "F.Cu" "B.Cu")
		(net "GND")
	)
	(via
		(at 449.677282 -258.516628)
		(size 0.4572)
		(drill 0.2032)
		(layers "F.Cu" "B.Cu")
		(net "GND")
	)
	(via
		(at 460.84998 -388.3406)
		(size 0.508)
		(drill 0.254)
		(layers "F.Cu" "B.Cu")
		(net "GND")
	)
	(via
		(at 272.273014 -263.616694)
		(size 0.4572)
		(drill 0.2032)
		(layers "F.Cu" "B.Cu")
		(net "GND")
	)
	(via
		(at 338.824316 -407.638504)
		(size 0.4572)
		(drill 0.254)
		(layers "F.Cu" "B.Cu")
		(net "GND")
	)
	(via
		(at 351.231962 -283.219906)
		(size 0.4572)
		(drill 0.2032)
		(layers "F.Cu" "B.Cu")
		(net "GND")
	)
	(via
		(at 209.281014 -198.166736)
		(size 0.4572)
		(drill 0.2032)
		(layers "F.Cu" "B.Cu")
		(net "GND")
	)
	(via
		(at 335.255362 -279.964134)
		(size 0.4572)
		(drill 0.2032)
		(layers "F.Cu" "B.Cu")
		(net "GND")
	)
	(via
		(at 342.194134 -246.364506)
		(size 0.4572)
		(drill 0.2032)
		(layers "F.Cu" "B.Cu")
		(net "GND")
	)
	(via
		(at 194.193414 -215.166702)
		(size 0.4572)
		(drill 0.2032)
		(layers "F.Cu" "B.Cu")
		(net "GND")
	)
	(via
		(at 259.075682 -306.96662)
		(size 0.4572)
		(drill 0.2032)
		(layers "F.Cu" "B.Cu")
		(net "GND")
	)
	(via
		(at 310.207914 -285.716726)
		(size 0.4572)
		(drill 0.2032)
		(layers "F.Cu" "B.Cu")
		(net "GND")
	)
	(via
		(at 96.751394 -334.282034)
		(size 0.49022)
		(drill 0.254)
		(layers "F.Cu" "B.Cu")
		(net "GND")
	)
	(via
		(at 44.754546 -206.666592)
		(size 0.4572)
		(drill 0.2032)
		(layers "F.Cu" "B.Cu")
		(net "GND")
	)
	(via
		(at 453.121014 -242.3668)
		(size 0.4572)
		(drill 0.2032)
		(layers "F.Cu" "B.Cu")
		(net "GND")
	)
	(via
		(at 182.549546 -208.366614)
		(size 0.4572)
		(drill 0.2032)
		(layers "F.Cu" "B.Cu")
		(net "GND")
	)
	(via
		(at 358.280462 -272.639282)
		(size 0.4572)
		(drill 0.2032)
		(layers "F.Cu" "B.Cu")
		(net "GND")
	)
	(via
		(at 450.911214 -203.266802)
		(size 0.4572)
		(drill 0.2032)
		(layers "F.Cu" "B.Cu")
		(net "GND")
	)
	(via
		(at 376.893582 -407.638504)
		(size 0.4572)
		(drill 0.254)
		(layers "F.Cu" "B.Cu")
		(net "GND")
	)
	(via
		(at 22.123146 -292.516814)
		(size 0.4572)
		(drill 0.2032)
		(layers "F.Cu" "B.Cu")
		(net "GND")
	)
	(via
		(at 31.751778 -98.570034)
		(size 0.508)
		(drill 0.254)
		(layers "F.Cu" "B.Cu")
		(net "GND")
	)
	(via
		(at 145.722086 -400.224244)
		(size 0.4572)
		(drill 0.254)
		(layers "F.Cu" "B.Cu")
		(net "GND")
	)
	(via
		(at 299.004482 -221.116652)
		(size 0.4572)
		(drill 0.2032)
		(layers "F.Cu" "B.Cu")
		(net "GND")
	)
	(via
		(at 212.724746 -300.166786)
		(size 0.4572)
		(drill 0.2032)
		(layers "F.Cu" "B.Cu")
		(net "GND")
	)
	(via
		(at 213.1568 -110.3122)
		(size 0.508)
		(drill 0.254)
		(layers "F.Cu" "B.Cu")
		(net "GND")
	)
	(via
		(at 43.520614 -305.266598)
		(size 0.4572)
		(drill 0.2032)
		(layers "F.Cu" "B.Cu")
		(net "GND")
	)
	(via
		(at 54.508146 -307.816758)
		(size 0.4572)
		(drill 0.2032)
		(layers "F.Cu" "B.Cu")
		(net "GND")
	)
	(via
		(at 87.315294 -265.314176)
		(size 0.4572)
		(drill 0.2032)
		(layers "F.Cu" "B.Cu")
		(net "GND")
	)
	(via
		(at 56.83885 -145.829274)
		(size 0.49022)
		(drill 0.254)
		(layers "F.Cu" "B.Cu")
		(net "GND")
	)
	(via
		(at 462.555082 -291.666676)
		(size 0.4572)
		(drill 0.2032)
		(layers "F.Cu" "B.Cu")
		(net "GND")
	)
	(via
		(at 212.724746 -290.816792)
		(size 0.4572)
		(drill 0.2032)
		(layers "F.Cu" "B.Cu")
		(net "GND")
	)
	(via
		(at 449.677282 -196.466714)
		(size 0.4572)
		(drill 0.2032)
		(layers "F.Cu" "B.Cu")
		(net "GND")
	)
	(via
		(at 194.193414 -312.91657)
		(size 0.4572)
		(drill 0.2032)
		(layers "F.Cu" "B.Cu")
		(net "GND")
	)
	(via
		(at 437.2356 -95.113348)
		(size 0.508)
		(drill 0.254)
		(layers "F.Cu" "B.Cu")
		(net "GND")
	)
	(via
		(at 159.918146 -223.666558)
		(size 0.4572)
		(drill 0.2032)
		(layers "F.Cu" "B.Cu")
		(net "GND")
	)
	(via
		(at 427.045882 -250.866656)
		(size 0.4572)
		(drill 0.2032)
		(layers "F.Cu" "B.Cu")
		(net "GND")
	)
	(via
		(at 59.250072 -436.347362)
		(size 0.4572)
		(drill 0.2032)
		(layers "F.Cu" "B.Cu")
		(net "GND")
	)
	(via
		(at 331.067918 -55.028846)
		(size 0.4572)
		(drill 0.2032)
		(layers "F.Cu" "B.Cu")
		(net "GND")
	)
	(via
		(at 323.053964 -441.225432)
		(size 0.508)
		(drill 0.254)
		(layers "F.Cu" "B.Cu")
		(net "GND")
	)
	(via
		(at 387.414516 -257.98907)
		(size 0.4572)
		(drill 0.2032)
		(layers "F.Cu" "B.Cu")
		(net "GND")
	)
	(via
		(at 361.569762 -263.686544)
		(size 0.4572)
		(drill 0.2032)
		(layers "F.Cu" "B.Cu")
		(net "GND")
	)
	(via
		(at 194.193414 -244.066568)
		(size 0.4572)
		(drill 0.2032)
		(layers "F.Cu" "B.Cu")
		(net "GND")
	)
	(via
		(at 372.377462 -267.755878)
		(size 0.4572)
		(drill 0.2032)
		(layers "F.Cu" "B.Cu")
		(net "GND")
	)
	(via
		(at 350.868742 -255.231392)
		(size 0.4572)
		(drill 0.2032)
		(layers "F.Cu" "B.Cu")
		(net "GND")
	)
	(via
		(at 419.502082 -228.766624)
		(size 0.4572)
		(drill 0.2032)
		(layers "F.Cu" "B.Cu")
		(net "GND")
	)
	(via
		(at 134.349998 -426.69968)
		(size 0.4572)
		(drill 0.2032)
		(layers "F.Cu" "B.Cu")
		(net "GND")
	)
	(via
		(at 66.152014 -269.566644)
		(size 0.4572)
		(drill 0.2032)
		(layers "F.Cu" "B.Cu")
		(net "GND")
	)
	(via
		(at 137.014966 -247.178322)
		(size 0.4572)
		(drill 0.2032)
		(layers "F.Cu" "B.Cu")
		(net "GND")
	)
	(via
		(at 437.308752 -323.429376)
		(size 0.4572)
		(drill 0.2032)
		(layers "F.Cu" "B.Cu")
		(net "GND")
	)
	(via
		(at 40.975534 -391.377932)
		(size 0.508)
		(drill 0.254)
		(layers "F.Cu" "B.Cu")
		(net "GND")
	)
	(via
		(at 147.349972 -427.851316)
		(size 0.4572)
		(drill 0.2032)
		(layers "F.Cu" "B.Cu")
		(net "GND")
	)
	(via
		(at 334.385412 -23.61438)
		(size 0.508)
		(drill 0.254)
		(layers "F.Cu" "B.Cu")
		(net "GND")
	)
	(via
		(at 434.844952 -386.321554)
		(size 0.508)
		(drill 0.254)
		(layers "F.Cu" "B.Cu")
		(net "GND")
	)
	(via
		(at 277.607014 -240.666778)
		(size 0.4572)
		(drill 0.2032)
		(layers "F.Cu" "B.Cu")
		(net "GND")
	)
	(via
		(at 371.764306 -169.078148)
		(size 0.508)
		(drill 0.254)
		(layers "F.Cu" "B.Cu")
		(net "GND")
	)
	(via
		(at 342.250014 -428.851314)
		(size 0.4572)
		(drill 0.2032)
		(layers "F.Cu" "B.Cu")
		(net "GND")
	)
	(via
		(at 66.152014 -215.166702)
		(size 0.4572)
		(drill 0.2032)
		(layers "F.Cu" "B.Cu")
		(net "GND")
	)
	(via
		(at 66.152014 -295.916604)
		(size 0.4572)
		(drill 0.2032)
		(layers "F.Cu" "B.Cu")
		(net "GND")
	)
	(via
		(at 419.502082 -277.216616)
		(size 0.4572)
		(drill 0.2032)
		(layers "F.Cu" "B.Cu")
		(net "GND")
	)
	(via
		(at 153.242518 -187.55741)
		(size 0.508)
		(drill 0.254)
		(layers "F.Cu" "B.Cu")
		(net "GND")
	)
	(via
		(at 179.35575 -114.975386)
		(size 0.4572)
		(drill 0.254)
		(layers "F.Cu" "B.Cu")
		(net "GND")
	)
	(via
		(at 141.400022 -403.249892)
		(size 0.4572)
		(drill 0.254)
		(layers "F.Cu" "B.Cu")
		(net "GND")
	)
	(via
		(at 368.148616 -279.964134)
		(size 0.4572)
		(drill 0.2032)
		(layers "F.Cu" "B.Cu")
		(net "GND")
	)
	(via
		(at 48.854614 -241.516662)
		(size 0.4572)
		(drill 0.2032)
		(layers "F.Cu" "B.Cu")
		(net "GND")
	)
	(via
		(at 18.679414 -215.166702)
		(size 0.4572)
		(drill 0.2032)
		(layers "F.Cu" "B.Cu")
		(net "GND")
	)
	(via
		(at 409.349956 -436.051198)
		(size 0.4572)
		(drill 0.2032)
		(layers "F.Cu" "B.Cu")
		(net "GND")
	)
	(via
		(at 311.882282 -289.966654)
		(size 0.4572)
		(drill 0.2032)
		(layers "F.Cu" "B.Cu")
		(net "GND")
	)
	(via
		(at 58.608214 -194.766692)
		(size 0.4572)
		(drill 0.2032)
		(layers "F.Cu" "B.Cu")
		(net "GND")
	)
	(via
		(at 121.148094 -286.475424)
		(size 0.4572)
		(drill 0.2032)
		(layers "F.Cu" "B.Cu")
		(net "GND")
	)
	(via
		(at 191.983614 -308.666642)
		(size 0.4572)
		(drill 0.2032)
		(layers "F.Cu" "B.Cu")
		(net "GND")
	)
	(via
		(at 136.619742 -409.396184)
		(size 0.4572)
		(drill 0.254)
		(layers "F.Cu" "B.Cu")
		(net "GND")
	)
	(via
		(at 63.942214 -280.61666)
		(size 0.4572)
		(drill 0.2032)
		(layers "F.Cu" "B.Cu")
		(net "GND")
	)
	(via
		(at 374.257316 -254.733552)
		(size 0.4572)
		(drill 0.2032)
		(layers "F.Cu" "B.Cu")
		(net "GND")
	)
	(via
		(at 99.062794 -284.033722)
		(size 0.4572)
		(drill 0.2032)
		(layers "F.Cu" "B.Cu")
		(net "GND")
	)
	(via
		(at 171.86275 -210.066636)
		(size 0.4572)
		(drill 0.2032)
		(layers "F.Cu" "B.Cu")
		(net "GND")
	)
	(via
		(at 102.991412 -60.128404)
		(size 0.508)
		(drill 0.254)
		(layers "F.Cu" "B.Cu")
		(net "GND")
	)
	(via
		(at 56.744362 -168.86428)
		(size 0.508)
		(drill 0.254)
		(layers "F.Cu" "B.Cu")
		(net "GND")
	)
	(via
		(at 40.256968 -10.16508)
		(size 0.508)
		(drill 0.254)
		(layers "F.Cu" "B.Cu")
		(net "GND")
	)
	(via
		(at 274.163282 -272.966688)
		(size 0.4572)
		(drill 0.2032)
		(layers "F.Cu" "B.Cu")
		(net "GND")
	)
	(via
		(at 258.572 -67.020948)
		(size 0.508)
		(drill 0.254)
		(layers "F.Cu" "B.Cu")
		(net "GND")
	)
	(via
		(at 84.250022 -431.451258)
		(size 0.4572)
		(drill 0.2032)
		(layers "F.Cu" "B.Cu")
		(net "GND")
	)
	(via
		(at 354.41128 -233.34218)
		(size 0.4572)
		(drill 0.2032)
		(layers "F.Cu" "B.Cu")
		(net "GND")
	)
	(via
		(at 85.905594 -285.661354)
		(size 0.4572)
		(drill 0.2032)
		(layers "F.Cu" "B.Cu")
		(net "GND")
	)
	(via
		(at 2.764536 -279.830022)
		(size 0.508)
		(drill 0.254)
		(layers "F.Cu" "B.Cu")
		(net "GND")
	)
	(via
		(at 28.433014 -233.86669)
		(size 0.4572)
		(drill 0.2032)
		(layers "F.Cu" "B.Cu")
		(net "GND")
	)
	(via
		(at 392.34999 -434.899562)
		(size 0.4572)
		(drill 0.2032)
		(layers "F.Cu" "B.Cu")
		(net "GND")
	)
	(via
		(at 26.223214 -314.616592)
		(size 0.4572)
		(drill 0.2032)
		(layers "F.Cu" "B.Cu")
		(net "GND")
	)
	(via
		(at 435.823614 -220.266768)
		(size 0.4572)
		(drill 0.2032)
		(layers "F.Cu" "B.Cu")
		(net "GND")
	)
	(via
		(at 0.76454 -46.560232)
		(size 0.508)
		(drill 0.254)
		(layers "F.Cu" "B.Cu")
		(net "GND")
	)
	(via
		(at 270.063214 -278.066754)
		(size 0.4572)
		(drill 0.2032)
		(layers "F.Cu" "B.Cu")
		(net "GND")
	)
	(via
		(at 69.179694 -30.541722)
		(size 0.508)
		(drill 0.254)
		(layers "F.Cu" "B.Cu")
		(net "GND")
	)
	(via
		(at 136.545066 -225.203258)
		(size 0.4572)
		(drill 0.2032)
		(layers "F.Cu" "B.Cu")
		(net "GND")
	)
	(via
		(at 56.182514 -314.616592)
		(size 0.4572)
		(drill 0.2032)
		(layers "F.Cu" "B.Cu")
		(net "GND")
	)
	(via
		(at 279.816814 -265.316716)
		(size 0.4572)
		(drill 0.2032)
		(layers "F.Cu" "B.Cu")
		(net "GND")
	)
	(via
		(at 299.004482 -294.216582)
		(size 0.4572)
		(drill 0.2032)
		(layers "F.Cu" "B.Cu")
		(net "GND")
	)
	(via
		(at 59.352942 -19.13636)
		(size 0.508)
		(drill 0.254)
		(layers "F.Cu" "B.Cu")
		(net "GND")
	)
	(via
		(at 95.077026 -409.396184)
		(size 0.4572)
		(drill 0.254)
		(layers "F.Cu" "B.Cu")
		(net "GND")
	)
	(via
		(at 339.098128 -403.883876)
		(size 0.4064)
		(drill 0.2032)
		(layers "F.Cu" "B.Cu")
		(net "GND")
	)
	(via
		(at 26.223214 -239.81664)
		(size 0.4572)
		(drill 0.2032)
		(layers "F.Cu" "B.Cu")
		(net "GND")
	)
	(via
		(at 277.607014 -212.616796)
		(size 0.4572)
		(drill 0.2032)
		(layers "F.Cu" "B.Cu")
		(net "GND")
	)
	(via
		(at 264.729214 -270.416782)
		(size 0.4572)
		(drill 0.2032)
		(layers "F.Cu" "B.Cu")
		(net "GND")
	)
	(via
		(at 434.589682 -239.81664)
		(size 0.4572)
		(drill 0.2032)
		(layers "F.Cu" "B.Cu")
		(net "GND")
	)
	(via
		(at 445.866012 -59.316112)
		(size 0.508)
		(drill 0.254)
		(layers "F.Cu" "B.Cu")
		(net "GND")
	)
	(via
		(at 377.436634 -235.783882)
		(size 0.4572)
		(drill 0.2032)
		(layers "F.Cu" "B.Cu")
		(net "GND")
	)
	(via
		(at 347.473016 -275.08073)
		(size 0.4572)
		(drill 0.2032)
		(layers "F.Cu" "B.Cu")
		(net "GND")
	)
	(via
		(at 434.589682 -262.76681)
		(size 0.4572)
		(drill 0.2032)
		(layers "F.Cu" "B.Cu")
		(net "GND")
	)
	(via
		(at 137.124694 -253.919736)
		(size 0.4318)
		(drill 0.2032)
		(layers "F.Cu" "B.Cu")
		(net "GND")
	)
	(via
		(at 180.339746 -304.416714)
		(size 0.4572)
		(drill 0.2032)
		(layers "F.Cu" "B.Cu")
		(net "GND")
	)
	(via
		(at 46.964346 -261.916672)
		(size 0.4572)
		(drill 0.2032)
		(layers "F.Cu" "B.Cu")
		(net "GND")
	)
	(via
		(at 169.352214 -211.766658)
		(size 0.4572)
		(drill 0.2032)
		(layers "F.Cu" "B.Cu")
		(net "GND")
	)
	(via
		(at 449.677282 -306.96662)
		(size 0.4572)
		(drill 0.2032)
		(layers "F.Cu" "B.Cu")
		(net "GND")
	)
	(via
		(at 123.857766 -226.017328)
		(size 0.4572)
		(drill 0.2032)
		(layers "F.Cu" "B.Cu")
		(net "GND")
	)
	(via
		(at 54.508146 -250.016772)
		(size 0.4572)
		(drill 0.2032)
		(layers "F.Cu" "B.Cu")
		(net "GND")
	)
	(via
		(at 335.145634 -222.761556)
		(size 0.4572)
		(drill 0.2032)
		(layers "F.Cu" "B.Cu")
		(net "GND")
	)
	(via
		(at 349.352362 -278.336502)
		(size 0.4572)
		(drill 0.2032)
		(layers "F.Cu" "B.Cu")
		(net "GND")
	)
	(via
		(at 320.444876 -407.638504)
		(size 0.4572)
		(drill 0.254)
		(layers "F.Cu" "B.Cu")
		(net "GND")
	)
	(via
		(at 420.7637 -165.883844)
		(size 0.508)
		(drill 0.254)
		(layers "F.Cu" "B.Cu")
		(net "GND")
	)
	(via
		(at 161.038286 -400.224244)
		(size 0.4572)
		(drill 0.254)
		(layers "F.Cu" "B.Cu")
		(net "GND")
	)
	(via
		(at 285.150814 -273.816572)
		(size 0.4572)
		(drill 0.2032)
		(layers "F.Cu" "B.Cu")
		(net "GND")
	)
	(via
		(at 464.764882 -316.316614)
		(size 0.4572)
		(drill 0.2032)
		(layers "F.Cu" "B.Cu")
		(net "GND")
	)
	(via
		(at 423.173652 -217.716608)
		(size 0.4572)
		(drill 0.2032)
		(layers "F.Cu" "B.Cu")
		(net "GND")
	)
	(via
		(at 94.715838 -407.00452)
		(size 0.4064)
		(drill 0.2032)
		(layers "F.Cu" "B.Cu")
		(net "GND")
	)
	(via
		(at 207.071214 -297.616626)
		(size 0.4572)
		(drill 0.2032)
		(layers "F.Cu" "B.Cu")
		(net "GND")
	)
	(via
		(at 182.549546 -229.616762)
		(size 0.4572)
		(drill 0.2032)
		(layers "F.Cu" "B.Cu")
		(net "GND")
	)
	(via
		(at 457.221082 -194.766692)
		(size 0.4572)
		(drill 0.2032)
		(layers "F.Cu" "B.Cu")
		(net "GND")
	)
	(via
		(at 432.379882 -213.46668)
		(size 0.4572)
		(drill 0.2032)
		(layers "F.Cu" "B.Cu")
		(net "GND")
	)
	(via
		(at 384.955034 -240.667286)
		(size 0.4318)
		(drill 0.2032)
		(layers "F.Cu" "B.Cu")
		(net "GND")
	)
	(via
		(at 334.315562 -279.964134)
		(size 0.4572)
		(drill 0.2032)
		(layers "F.Cu" "B.Cu")
		(net "GND")
	)
	(via
		(at 48.854614 -288.266632)
		(size 0.4572)
		(drill 0.2032)
		(layers "F.Cu" "B.Cu")
		(net "GND")
	)
	(via
		(at 130.906012 -249.620024)
		(size 0.4572)
		(drill 0.2032)
		(layers "F.Cu" "B.Cu")
		(net "GND")
	)
	(via
		(at 422.17848 -153.614628)
		(size 0.508)
		(drill 0.254)
		(layers "F.Cu" "B.Cu")
		(net "GND")
	)
	(via
		(at 295.72204 -368.407442)
		(size 0.508)
		(drill 0.254)
		(layers "F.Cu" "B.Cu")
		(net "GND")
	)
	(via
		(at 152.08504 -51.742848)
		(size 0.508)
		(drill 0.254)
		(layers "F.Cu" "B.Cu")
		(net "GND")
	)
	(via
		(at 212.471508 -41.034462)
		(size 0.508)
		(drill 0.254)
		(layers "F.Cu" "B.Cu")
		(net "GND")
	)
	(via
		(at 28.433014 -194.766692)
		(size 0.4572)
		(drill 0.2032)
		(layers "F.Cu" "B.Cu")
		(net "GND")
	)
	(via
		(at 407.88717 -410.030168)
		(size 0.4064)
		(drill 0.2032)
		(layers "F.Cu" "B.Cu")
		(net "GND")
	)
	(via
		(at 407.984198 -404.51786)
		(size 0.4572)
		(drill 0.254)
		(layers "F.Cu" "B.Cu")
		(net "GND")
	)
	(via
		(at 296.794682 -196.466714)
		(size 0.4572)
		(drill 0.2032)
		(layers "F.Cu" "B.Cu")
		(net "GND")
	)
	(via
		(at 352.214942 -297.07078)
		(size 0.508)
		(drill 0.254)
		(layers "F.Cu" "B.Cu")
		(net "GND")
	)
	(via
		(at 373.67972 -330.303378)
		(size 0.508)
		(drill 0.254)
		(layers "F.Cu" "B.Cu")
		(net "GND")
	)
	(via
		(at 184.439814 -245.76659)
		(size 0.4572)
		(drill 0.2032)
		(layers "F.Cu" "B.Cu")
		(net "GND")
	)
	(via
		(at 384.015234 -235.783882)
		(size 0.4572)
		(drill 0.2032)
		(layers "F.Cu" "B.Cu")
		(net "GND")
	)
	(via
		(at 183.902096 -352.408236)
		(size 0.49022)
		(drill 0.254)
		(layers "F.Cu" "B.Cu")
		(net "GND")
	)
	(via
		(at 108.820966 -229.272846)
		(size 0.4572)
		(drill 0.2032)
		(layers "F.Cu" "B.Cu")
		(net "GND")
	)
	(via
		(at 471.03538 -43.784266)
		(size 0.508)
		(drill 0.254)
		(layers "F.Cu" "B.Cu")
		(net "GND")
	)
	(via
		(at 167.699436 -313.766708)
		(size 0.4572)
		(drill 0.2032)
		(layers "F.Cu" "B.Cu")
		(net "GND")
	)
	(via
		(at 144.463262 -401.492212)
		(size 0.4572)
		(drill 0.254)
		(layers "F.Cu" "B.Cu")
		(net "GND")
	)
	(via
		(at 135.714994 -282.405836)
		(size 0.4572)
		(drill 0.2032)
		(layers "F.Cu" "B.Cu")
		(net "GND")
	)
	(via
		(at 414.85947 -179.489354)
		(size 0.49022)
		(drill 0.254)
		(layers "F.Cu" "B.Cu")
		(net "GND")
	)
	(via
		(at 277.607014 -304.416714)
		(size 0.4572)
		(drill 0.2032)
		(layers "F.Cu" "B.Cu")
		(net "GND")
	)
	(via
		(at 41.310814 -288.266632)
		(size 0.4572)
		(drill 0.2032)
		(layers "F.Cu" "B.Cu")
		(net "GND")
	)
	(via
		(at 180.339746 -300.166786)
		(size 0.4572)
		(drill 0.2032)
		(layers "F.Cu" "B.Cu")
		(net "GND")
	)
	(via
		(at 194.193414 -207.51673)
		(size 0.4572)
		(drill 0.2032)
		(layers "F.Cu" "B.Cu")
		(net "GND")
	)
	(via
		(at 348.882462 -254.733552)
		(size 0.4572)
		(drill 0.2032)
		(layers "F.Cu" "B.Cu")
		(net "GND")
	)
	(via
		(at 404.920958 -400.224244)
		(size 0.4572)
		(drill 0.254)
		(layers "F.Cu" "B.Cu")
		(net "GND")
	)
	(via
		(at 439.923682 -245.76659)
		(size 0.4572)
		(drill 0.2032)
		(layers "F.Cu" "B.Cu")
		(net "GND")
	)
	(via
		(at 56.874918 -407.00452)
		(size 0.4064)
		(drill 0.2032)
		(layers "F.Cu" "B.Cu")
		(net "GND")
	)
	(via
		(at 41.310814 -291.666676)
		(size 0.4572)
		(drill 0.2032)
		(layers "F.Cu" "B.Cu")
		(net "GND")
	)
	(via
		(at 90.494866 -249.620024)
		(size 0.4572)
		(drill 0.2032)
		(layers "F.Cu" "B.Cu")
		(net "GND")
	)
	(via
		(at 90.25001 -428.851314)
		(size 0.4572)
		(drill 0.2032)
		(layers "F.Cu" "B.Cu")
		(net "GND")
	)
	(via
		(at 44.754546 -313.766708)
		(size 0.4572)
		(drill 0.2032)
		(layers "F.Cu" "B.Cu")
		(net "GND")
	)
	(via
		(at 422.945814 -304.416714)
		(size 0.4572)
		(drill 0.2032)
		(layers "F.Cu" "B.Cu")
		(net "GND")
	)
	(via
		(at 321.250056 -431.29962)
		(size 0.4572)
		(drill 0.2032)
		(layers "F.Cu" "B.Cu")
		(net "GND")
	)
	(via
		(at 422.945814 -250.016772)
		(size 0.4572)
		(drill 0.2032)
		(layers "F.Cu" "B.Cu")
		(net "GND")
	)
	(via
		(at 81.01965 -406.370536)
		(size 0.4572)
		(drill 0.254)
		(layers "F.Cu" "B.Cu")
		(net "GND")
	)
	(via
		(at 43.520614 -207.51673)
		(size 0.4572)
		(drill 0.2032)
		(layers "F.Cu" "B.Cu")
		(net "GND")
	)
	(via
		(at 383.545334 -243.108988)
		(size 0.4572)
		(drill 0.2032)
		(layers "F.Cu" "B.Cu")
		(net "GND")
	)
	(via
		(at 15.339822 -108.28274)
		(size 0.508)
		(drill 0.254)
		(layers "F.Cu" "B.Cu")
		(net "GND")
	)
	(via
		(at 440.00928 -7.153148)
		(size 0.508)
		(drill 0.254)
		(layers "F.Cu" "B.Cu")
		(net "GND")
	)
	(via
		(at 419.502082 -232.166668)
		(size 0.4572)
		(drill 0.2032)
		(layers "F.Cu" "B.Cu")
		(net "GND")
	)
	(via
		(at 167.461946 -300.166786)
		(size 0.4572)
		(drill 0.2032)
		(layers "F.Cu" "B.Cu")
		(net "GND")
	)
	(via
		(at 349.909638 -50.191416)
		(size 0.49022)
		(drill 0.254)
		(layers "F.Cu" "B.Cu")
		(net "GND")
	)
	(via
		(at 105.641394 -271.011396)
		(size 0.4572)
		(drill 0.2032)
		(layers "F.Cu" "B.Cu")
		(net "GND")
	)
	(via
		(at 186.649614 -308.666642)
		(size 0.4572)
		(drill 0.2032)
		(layers "F.Cu" "B.Cu")
		(net "GND")
	)
	(via
		(at 411.958282 -249.166634)
		(size 0.4572)
		(drill 0.2032)
		(layers "F.Cu" "B.Cu")
		(net "GND")
	)
	(via
		(at 259.075682 -233.86669)
		(size 0.4572)
		(drill 0.2032)
		(layers "F.Cu" "B.Cu")
		(net "GND")
	)
	(via
		(at 416.128962 -360.937556)
		(size 0.49022)
		(drill 0.254)
		(layers "F.Cu" "B.Cu")
		(net "GND")
	)
	(via
		(at 309.547768 -400.858228)
		(size 0.4064)
		(drill 0.2032)
		(layers "F.Cu" "B.Cu")
		(net "GND")
	)
	(via
		(at 186.649614 -219.41663)
		(size 0.4572)
		(drill 0.2032)
		(layers "F.Cu" "B.Cu")
		(net "GND")
	)
	(via
		(at 431.000154 -130.964178)
		(size 0.508)
		(drill 0.254)
		(layers "F.Cu" "B.Cu")
		(net "GND")
	)
	(via
		(at 345.283028 -326.910192)
		(size 0.508)
		(drill 0.254)
		(layers "F.Cu" "B.Cu")
		(net "GND")
	)
	(via
		(at 450.911214 -244.916706)
		(size 0.4572)
		(drill 0.2032)
		(layers "F.Cu" "B.Cu")
		(net "GND")
	)
	(via
		(at 179.105814 -305.266598)
		(size 0.4572)
		(drill 0.2032)
		(layers "F.Cu" "B.Cu")
		(net "GND")
	)
	(via
		(at 346.063062 -274.266914)
		(size 0.4572)
		(drill 0.2032)
		(layers "F.Cu" "B.Cu")
		(net "GND")
	)
	(via
		(at 202.971146 -221.96679)
		(size 0.4572)
		(drill 0.2032)
		(layers "F.Cu" "B.Cu")
		(net "GND")
	)
	(via
		(at 379.896116 -262.872474)
		(size 0.4572)
		(drill 0.2032)
		(layers "F.Cu" "B.Cu")
		(net "GND")
	)
	(via
		(at 412.935166 -321.758564)
		(size 0.4572)
		(drill 0.2032)
		(layers "F.Cu" "B.Cu")
		(net "GND")
	)
	(via
		(at 376.02668 -244.73662)
		(size 0.4572)
		(drill 0.2032)
		(layers "F.Cu" "B.Cu")
		(net "GND")
	)
	(via
		(at 355.6 -417.159948)
		(size 0.508)
		(drill 0.254)
		(layers "F.Cu" "B.Cu")
		(net "GND")
	)
	(via
		(at 136.05002 -77.876908)
		(size 0.508)
		(drill 0.254)
		(layers "F.Cu" "B.Cu")
		(net "GND")
	)
	(via
		(at 52.298346 -281.466798)
		(size 0.4572)
		(drill 0.2032)
		(layers "F.Cu" "B.Cu")
		(net "GND")
	)
	(via
		(at 337.604862 -262.872474)
		(size 0.4572)
		(drill 0.2032)
		(layers "F.Cu" "B.Cu")
		(net "GND")
	)
	(via
		(at 33.767014 -278.916638)
		(size 0.4572)
		(drill 0.2032)
		(layers "F.Cu" "B.Cu")
		(net "GND")
	)
	(via
		(at 356.4509 -385.17449)
		(size 0.508)
		(drill 0.254)
		(layers "F.Cu" "B.Cu")
		(net "GND")
	)
	(via
		(at 383.075434 -216.25052)
		(size 0.4572)
		(drill 0.2032)
		(layers "F.Cu" "B.Cu")
		(net "GND")
	)
	(via
		(at 27.662886 -166.351204)
		(size 0.508)
		(drill 0.254)
		(layers "F.Cu" "B.Cu")
		(net "GND")
	)
	(via
		(at 24.332946 -244.916706)
		(size 0.4572)
		(drill 0.2032)
		(layers "F.Cu" "B.Cu")
		(net "GND")
	)
	(via
		(at 406.179782 -401.492212)
		(size 0.4572)
		(drill 0.254)
		(layers "F.Cu" "B.Cu")
		(net "GND")
	)
	(via
		(at 315.57722 -410.664152)
		(size 0.4572)
		(drill 0.254)
		(layers "F.Cu" "B.Cu")
		(net "GND")
	)
	(via
		(at 415.402014 -229.616762)
		(size 0.4572)
		(drill 0.2032)
		(layers "F.Cu" "B.Cu")
		(net "GND")
	)
	(via
		(at 399.484596 -19.759422)
		(size 0.508)
		(drill 0.254)
		(layers "F.Cu" "B.Cu")
		(net "GND")
	)
	(via
		(at 91.904312 -232.528364)
		(size 0.4572)
		(drill 0.2032)
		(layers "F.Cu" "B.Cu")
		(net "GND")
	)
	(via
		(at 383.075434 -242.294918)
		(size 0.4572)
		(drill 0.2032)
		(layers "F.Cu" "B.Cu")
		(net "GND")
	)
	(via
		(at 257.185414 -300.166786)
		(size 0.4572)
		(drill 0.2032)
		(layers "F.Cu" "B.Cu")
		(net "GND")
	)
	(via
		(at 110.23092 -241.481356)
		(size 0.4572)
		(drill 0.2032)
		(layers "F.Cu" "B.Cu")
		(net "GND")
	)
	(via
		(at 195.427346 -265.316716)
		(size 0.4572)
		(drill 0.2032)
		(layers "F.Cu" "B.Cu")
		(net "GND")
	)
	(via
		(at 129.659126 -336.765392)
		(size 0.49022)
		(drill 0.254)
		(layers "F.Cu" "B.Cu")
		(net "GND")
	)
	(via
		(at 9.245346 -304.416714)
		(size 0.4572)
		(drill 0.2032)
		(layers "F.Cu" "B.Cu")
		(net "GND")
	)
	(via
		(at 136.349994 -431.29962)
		(size 0.4572)
		(drill 0.2032)
		(layers "F.Cu" "B.Cu")
		(net "GND")
	)
	(via
		(at 180.957982 -26.240232)
		(size 0.508)
		(drill 0.254)
		(layers "F.Cu" "B.Cu")
		(net "GND")
	)
	(via
		(at 443.367414 -307.816758)
		(size 0.4572)
		(drill 0.2032)
		(layers "F.Cu" "B.Cu")
		(net "GND")
	)
	(via
		(at 300.238414 -225.36658)
		(size 0.4572)
		(drill 0.2032)
		(layers "F.Cu" "B.Cu")
		(net "GND")
	)
	(via
		(at 394.84681 -10.16508)
		(size 0.508)
		(drill 0.254)
		(layers "F.Cu" "B.Cu")
		(net "GND")
	)
	(via
		(at 190.093346 -278.066754)
		(size 0.4572)
		(drill 0.2032)
		(layers "F.Cu" "B.Cu")
		(net "GND")
	)
	(via
		(at 449.677282 -299.316648)
		(size 0.4572)
		(drill 0.2032)
		(layers "F.Cu" "B.Cu")
		(net "GND")
	)
	(via
		(at 357.092504 -369.137692)
		(size 0.508)
		(drill 0.254)
		(layers "F.Cu" "B.Cu")
		(net "GND")
	)
	(via
		(at 136.185148 -288.103056)
		(size 0.4572)
		(drill 0.2032)
		(layers "F.Cu" "B.Cu")
		(net "GND")
	)
	(via
		(at 271.936972 -73.279)
		(size 0.508)
		(drill 0.254)
		(layers "F.Cu" "B.Cu")
		(net "GND")
	)
	(via
		(at 427.045882 -202.416664)
		(size 0.4572)
		(drill 0.2032)
		(layers "F.Cu" "B.Cu")
		(net "GND")
	)
	(via
		(at 210.514946 -236.416596)
		(size 0.4572)
		(drill 0.2032)
		(layers "F.Cu" "B.Cu")
		(net "GND")
	)
	(via
		(at 373.787416 -253.919736)
		(size 0.4572)
		(drill 0.2032)
		(layers "F.Cu" "B.Cu")
		(net "GND")
	)
	(via
		(at 344.669872 -86.261194)
		(size 0.508)
		(drill 0.254)
		(layers "F.Cu" "B.Cu")
		(net "GND")
	)
	(via
		(at 352.758502 -353.86264)
		(size 0.508)
		(drill 0.254)
		(layers "F.Cu" "B.Cu")
		(net "GND")
	)
	(via
		(at 331.880718 -48.920146)
		(size 0.4572)
		(drill 0.2032)
		(layers "F.Cu" "B.Cu")
		(net "GND")
	)
	(via
		(at 52.298346 -212.616796)
		(size 0.4572)
		(drill 0.2032)
		(layers "F.Cu" "B.Cu")
		(net "GND")
	)
	(via
		(at 450.911214 -251.716794)
		(size 0.4572)
		(drill 0.2032)
		(layers "F.Cu" "B.Cu")
		(net "GND")
	)
	(via
		(at 164.018214 -221.116652)
		(size 0.4572)
		(drill 0.2032)
		(layers "F.Cu" "B.Cu")
		(net "GND")
	)
	(via
		(at 22.123146 -315.46673)
		(size 0.4572)
		(drill 0.2032)
		(layers "F.Cu" "B.Cu")
		(net "GND")
	)
	(via
		(at 143.34998 -430.299622)
		(size 0.4572)
		(drill 0.2032)
		(layers "F.Cu" "B.Cu")
		(net "GND")
	)
	(via
		(at 376.96648 -247.992138)
		(size 0.4572)
		(drill 0.2032)
		(layers "F.Cu" "B.Cu")
		(net "GND")
	)
	(via
		(at 145.349976 -439.651394)
		(size 0.4572)
		(drill 0.2032)
		(layers "F.Cu" "B.Cu")
		(net "GND")
	)
	(via
		(at 299.004482 -316.316614)
		(size 0.4572)
		(drill 0.2032)
		(layers "F.Cu" "B.Cu")
		(net "GND")
	)
	(via
		(at 277.607014 -216.016586)
		(size 0.4572)
		(drill 0.2032)
		(layers "F.Cu" "B.Cu")
		(net "GND")
	)
	(via
		(at 412.84398 -159.095948)
		(size 0.508)
		(drill 0.254)
		(layers "F.Cu" "B.Cu")
		(net "GND")
	)
	(via
		(at 419.502082 -299.316648)
		(size 0.4572)
		(drill 0.2032)
		(layers "F.Cu" "B.Cu")
		(net "GND")
	)
	(via
		(at 155.58008 -39.322248)
		(size 0.508)
		(drill 0.254)
		(layers "F.Cu" "B.Cu")
		(net "GND")
	)
	(via
		(at 82.250026 -430.147222)
		(size 0.4572)
		(drill 0.2032)
		(layers "F.Cu" "B.Cu")
		(net "GND")
	)
	(via
		(at 167.461946 -214.316564)
		(size 0.4572)
		(drill 0.2032)
		(layers "F.Cu" "B.Cu")
		(net "GND")
	)
	(via
		(at 9.245346 -290.816792)
		(size 0.4572)
		(drill 0.2032)
		(layers "F.Cu" "B.Cu")
		(net "GND")
	)
	(via
		(at 384.233928 -343.48293)
		(size 0.49022)
		(drill 0.254)
		(layers "F.Cu" "B.Cu")
		(net "GND")
	)
	(via
		(at 270.063214 -244.916706)
		(size 0.4572)
		(drill 0.2032)
		(layers "F.Cu" "B.Cu")
		(net "GND")
	)
	(via
		(at 379.896116 -267.755878)
		(size 0.4572)
		(drill 0.2032)
		(layers "F.Cu" "B.Cu")
		(net "GND")
	)
	(via
		(at 387.549898 -336.09407)
		(size 0.6604)
		(drill 0.3302)
		(layers "F.Cu" "B.Cu")
		(net "GND")
	)
	(via
		(at 435.823614 -292.516814)
		(size 0.4572)
		(drill 0.2032)
		(layers "F.Cu" "B.Cu")
		(net "GND")
	)
	(via
		(at 299.004482 -226.216718)
		(size 0.4572)
		(drill 0.2032)
		(layers "F.Cu" "B.Cu")
		(net "GND")
	)
	(via
		(at 307.782214 -278.066754)
		(size 0.4572)
		(drill 0.2032)
		(layers "F.Cu" "B.Cu")
		(net "GND")
	)
	(via
		(at 205.180946 -250.016772)
		(size 0.4572)
		(drill 0.2032)
		(layers "F.Cu" "B.Cu")
		(net "GND")
	)
	(via
		(at 125.267466 -239.853216)
		(size 0.4572)
		(drill 0.2032)
		(layers "F.Cu" "B.Cu")
		(net "GND")
	)
	(via
		(at 414.787588 -19.125438)
		(size 0.508)
		(drill 0.254)
		(layers "F.Cu" "B.Cu")
		(net "GND")
	)
	(via
		(at 171.868592 -420.97452)
		(size 0.508)
		(drill 0.254)
		(layers "F.Cu" "B.Cu")
		(net "GND")
	)
	(via
		(at 212.724746 -295.06672)
		(size 0.4572)
		(drill 0.2032)
		(layers "F.Cu" "B.Cu")
		(net "GND")
	)
	(via
		(at 31.876746 -214.316564)
		(size 0.4572)
		(drill 0.2032)
		(layers "F.Cu" "B.Cu")
		(net "GND")
	)
	(via
		(at 326.571356 -410.664152)
		(size 0.4572)
		(drill 0.254)
		(layers "F.Cu" "B.Cu")
		(net "GND")
	)
	(via
		(at 244.75694 -249.248168)
		(size 0.508)
		(drill 0.254)
		(layers "F.Cu" "B.Cu")
		(net "GND")
	)
	(via
		(at 370.497862 -287.28924)
		(size 0.4572)
		(drill 0.2032)
		(layers "F.Cu" "B.Cu")
		(net "GND")
	)
	(via
		(at 430.489614 -298.466764)
		(size 0.4572)
		(drill 0.2032)
		(layers "F.Cu" "B.Cu")
		(net "GND")
	)
	(via
		(at 453.121014 -296.766742)
		(size 0.4572)
		(drill 0.2032)
		(layers "F.Cu" "B.Cu")
		(net "GND")
	)
	(via
		(at 210.514946 -283.166566)
		(size 0.4572)
		(drill 0.2032)
		(layers "F.Cu" "B.Cu")
		(net "GND")
	)
	(via
		(at 276.373082 -282.316682)
		(size 0.4572)
		(drill 0.2032)
		(layers "F.Cu" "B.Cu")
		(net "GND")
	)
	(via
		(at 427.045882 -198.166736)
		(size 0.4572)
		(drill 0.2032)
		(layers "F.Cu" "B.Cu")
		(net "GND")
	)
	(via
		(at 457.994766 -92.022422)
		(size 0.508)
		(drill 0.254)
		(layers "F.Cu" "B.Cu")
		(net "GND")
	)
	(via
		(at 39.420546 -270.416782)
		(size 0.4572)
		(drill 0.2032)
		(layers "F.Cu" "B.Cu")
		(net "GND")
	)
	(via
		(at 254.975614 -195.616576)
		(size 0.4572)
		(drill 0.2032)
		(layers "F.Cu" "B.Cu")
		(net "GND")
	)
	(via
		(at 93.456506 -332.363826)
		(size 0.508)
		(drill 0.254)
		(layers "F.Cu" "B.Cu")
		(net "GND")
	)
	(via
		(at 167.461946 -306.116736)
		(size 0.4572)
		(drill 0.2032)
		(layers "F.Cu" "B.Cu")
		(net "GND")
	)
	(via
		(at 91.904566 -226.017328)
		(size 0.4572)
		(drill 0.2032)
		(layers "F.Cu" "B.Cu")
		(net "GND")
	)
	(via
		(at 338.250022 -432.451256)
		(size 0.4572)
		(drill 0.2032)
		(layers "F.Cu" "B.Cu")
		(net "GND")
	)
	(via
		(at 55.61584 -352.631248)
		(size 0.508)
		(drill 0.254)
		(layers "F.Cu" "B.Cu")
		(net "GND")
	)
	(via
		(at 441.26404 -93.505528)
		(size 0.508)
		(drill 0.254)
		(layers "F.Cu" "B.Cu")
		(net "GND")
	)
	(via
		(at 92.954348 -262.058658)
		(size 0.4572)
		(drill 0.2032)
		(layers "F.Cu" "B.Cu")
		(net "GND")
	)
	(via
		(at 424.4467 -6.07949)
		(size 0.508)
		(drill 0.254)
		(layers "F.Cu" "B.Cu")
		(net "GND")
	)
	(via
		(at 349.24238 -229.272846)
		(size 0.4572)
		(drill 0.2032)
		(layers "F.Cu" "B.Cu")
		(net "GND")
	)
	(via
		(at 326.48398 -401.492212)
		(size 0.4572)
		(drill 0.254)
		(layers "F.Cu" "B.Cu")
		(net "GND")
	)
	(via
		(at 16.789146 -268.71676)
		(size 0.4572)
		(drill 0.2032)
		(layers "F.Cu" "B.Cu")
		(net "GND")
	)
	(via
		(at 114.569748 -276.708616)
		(size 0.4572)
		(drill 0.2032)
		(layers "F.Cu" "B.Cu")
		(net "GND")
	)
	(via
		(at 261.285482 -233.86669)
		(size 0.4572)
		(drill 0.2032)
		(layers "F.Cu" "B.Cu")
		(net "GND")
	)
	(via
		(at 396.349982 -434.899562)
		(size 0.4572)
		(drill 0.2032)
		(layers "F.Cu" "B.Cu")
		(net "GND")
	)
	(via
		(at 419.730682 -272.966688)
		(size 0.4572)
		(drill 0.2032)
		(layers "F.Cu" "B.Cu")
		(net "GND")
	)
	(via
		(at 359.580434 -219.506038)
		(size 0.4572)
		(drill 0.2032)
		(layers "F.Cu" "B.Cu")
		(net "GND")
	)
	(via
		(at 95.350838 -403.883876)
		(size 0.4064)
		(drill 0.2032)
		(layers "F.Cu" "B.Cu")
		(net "GND")
	)
	(via
		(at 187.883546 -206.666592)
		(size 0.4572)
		(drill 0.2032)
		(layers "F.Cu" "B.Cu")
		(net "GND")
	)
	(via
		(at 322.064888 -407.00452)
		(size 0.4064)
		(drill 0.2032)
		(layers "F.Cu" "B.Cu")
		(net "GND")
	)
	(via
		(at 210.514946 -258.516628)
		(size 0.4572)
		(drill 0.2032)
		(layers "F.Cu" "B.Cu")
		(net "GND")
	)
	(via
		(at 379.786134 -244.73662)
		(size 0.4572)
		(drill 0.2032)
		(layers "F.Cu" "B.Cu")
		(net "GND")
	)
	(via
		(at 409.69692 -182.395368)
		(size 0.508)
		(drill 0.254)
		(layers "F.Cu" "B.Cu")
		(net "GND")
	)
	(via
		(at 57.586118 -18.502376)
		(size 0.508)
		(drill 0.254)
		(layers "F.Cu" "B.Cu")
		(net "GND")
	)
	(via
		(at 422.945814 -221.96679)
		(size 0.4572)
		(drill 0.2032)
		(layers "F.Cu" "B.Cu")
		(net "GND")
	)
	(via
		(at 124.279406 -400.224244)
		(size 0.4572)
		(drill 0.254)
		(layers "F.Cu" "B.Cu")
		(net "GND")
	)
	(via
		(at 306.764182 -210.066636)
		(size 0.4572)
		(drill 0.2032)
		(layers "F.Cu" "B.Cu")
		(net "GND")
	)
	(via
		(at 116.449348 -288.103056)
		(size 0.4572)
		(drill 0.2032)
		(layers "F.Cu" "B.Cu")
		(net "GND")
	)
	(via
		(at 169.13606 -216.866724)
		(size 0.4572)
		(drill 0.2032)
		(layers "F.Cu" "B.Cu")
		(net "GND")
	)
	(via
		(at 375.447306 -182.598568)
		(size 0.508)
		(drill 0.254)
		(layers "F.Cu" "B.Cu")
		(net "GND")
	)
	(via
		(at 181.407308 -54.152546)
		(size 0.508)
		(drill 0.254)
		(layers "F.Cu" "B.Cu")
		(net "GND")
	)
	(via
		(at 109.400848 -266.128246)
		(size 0.4572)
		(drill 0.2032)
		(layers "F.Cu" "B.Cu")
		(net "GND")
	)
	(via
		(at 167.461946 -267.016738)
		(size 0.4572)
		(drill 0.2032)
		(layers "F.Cu" "B.Cu")
		(net "GND")
	)
	(via
		(at 84.20481 -337.643216)
		(size 0.508)
		(drill 0.254)
		(layers "F.Cu" "B.Cu")
		(net "GND")
	)
	(via
		(at 157.386528 -204.96657)
		(size 0.4572)
		(drill 0.2032)
		(layers "F.Cu" "B.Cu")
		(net "GND")
	)
	(via
		(at 448.01282 -377.896628)
		(size 0.49022)
		(drill 0.254)
		(layers "F.Cu" "B.Cu")
		(net "GND")
	)
	(via
		(at 286.051752 -323.429376)
		(size 0.4572)
		(drill 0.2032)
		(layers "F.Cu" "B.Cu")
		(net "GND")
	)
	(via
		(at 450.911214 -292.516814)
		(size 0.4572)
		(drill 0.2032)
		(layers "F.Cu" "B.Cu")
		(net "GND")
	)
	(via
		(at 327.83018 -410.664152)
		(size 0.4572)
		(drill 0.254)
		(layers "F.Cu" "B.Cu")
		(net "GND")
	)
	(via
		(at 11.135614 -221.116652)
		(size 0.4572)
		(drill 0.2032)
		(layers "F.Cu" "B.Cu")
		(net "GND")
	)
	(via
		(at 115.426236 -259.051044)
		(size 0.4572)
		(drill 0.2032)
		(layers "F.Cu" "B.Cu")
		(net "GND")
	)
	(via
		(at 300.238414 -283.166566)
		(size 0.4572)
		(drill 0.2032)
		(layers "F.Cu" "B.Cu")
		(net "GND")
	)
	(via
		(at 339.844634 -226.017328)
		(size 0.4572)
		(drill 0.2032)
		(layers "F.Cu" "B.Cu")
		(net "GND")
	)
	(via
		(at 194.193414 -264.466578)
		(size 0.4572)
		(drill 0.2032)
		(layers "F.Cu" "B.Cu")
		(net "GND")
	)
	(via
		(at 23.113492 -386.444998)
		(size 0.508)
		(drill 0.254)
		(layers "F.Cu" "B.Cu")
		(net "GND")
	)
	(via
		(at 345.593416 -268.569694)
		(size 0.4572)
		(drill 0.2032)
		(layers "F.Cu" "B.Cu")
		(net "GND")
	)
	(via
		(at 135.176514 -407.00452)
		(size 0.4064)
		(drill 0.2032)
		(layers "F.Cu" "B.Cu")
		(net "GND")
	)
	(via
		(at 53.267102 -9.424924)
		(size 0.508)
		(drill 0.254)
		(layers "F.Cu" "B.Cu")
		(net "GND")
	)
	(via
		(at 169.352214 -244.066568)
		(size 0.4572)
		(drill 0.2032)
		(layers "F.Cu" "B.Cu")
		(net "GND")
	)
	(via
		(at 129.032254 -365.421926)
		(size 0.508)
		(drill 0.254)
		(layers "F.Cu" "B.Cu")
		(net "GND")
	)
	(via
		(at 70.936358 -25.192482)
		(size 0.508)
		(drill 0.254)
		(layers "F.Cu" "B.Cu")
		(net "GND")
	)
	(via
		(at 438.033414 -261.916672)
		(size 0.4572)
		(drill 0.2032)
		(layers "F.Cu" "B.Cu")
		(net "GND")
	)
	(via
		(at 167.461946 -197.316598)
		(size 0.4572)
		(drill 0.2032)
		(layers "F.Cu" "B.Cu")
		(net "GND")
	)
	(via
		(at 363.373416 -252.221492)
		(size 0.4572)
		(drill 0.2032)
		(layers "F.Cu" "B.Cu")
		(net "GND")
	)
	(via
		(at 138.34999 -437.49976)
		(size 0.4572)
		(drill 0.2032)
		(layers "F.Cu" "B.Cu")
		(net "GND")
	)
	(via
		(at 242.871752 -125.827536)
		(size 0.508)
		(drill 0.254)
		(layers "F.Cu" "B.Cu")
		(net "GND")
	)
	(via
		(at 121.216166 -401.492212)
		(size 0.4572)
		(drill 0.254)
		(layers "F.Cu" "B.Cu")
		(net "GND")
	)
	(via
		(at 51.272694 -353.187)
		(size 0.49022)
		(drill 0.254)
		(layers "F.Cu" "B.Cu")
		(net "GND")
	)
	(via
		(at 409.349956 -437.34736)
		(size 0.4572)
		(drill 0.2032)
		(layers "F.Cu" "B.Cu")
		(net "GND")
	)
	(via
		(at 67.202812 -40.437562)
		(size 0.508)
		(drill 0.254)
		(layers "F.Cu" "B.Cu")
		(net "GND")
	)
	(via
		(at 58.725562 -159.56788)
		(size 0.508)
		(drill 0.254)
		(layers "F.Cu" "B.Cu")
		(net "GND")
	)
	(via
		(at 415.209482 -354.180394)
		(size 0.508)
		(drill 0.254)
		(layers "F.Cu" "B.Cu")
		(net "GND")
	)
	(via
		(at 195.427346 -260.21665)
		(size 0.4572)
		(drill 0.2032)
		(layers "F.Cu" "B.Cu")
		(net "GND")
	)
	(via
		(at 352.531934 -223.575626)
		(size 0.4572)
		(drill 0.2032)
		(layers "F.Cu" "B.Cu")
		(net "GND")
	)
	(via
		(at 353.581462 -269.38351)
		(size 0.4572)
		(drill 0.2032)
		(layers "F.Cu" "B.Cu")
		(net "GND")
	)
	(via
		(at 369.526566 -365.691928)
		(size 0.508)
		(drill 0.254)
		(layers "F.Cu" "B.Cu")
		(net "GND")
	)
	(via
		(at 434.589682 -271.266666)
		(size 0.4572)
		(drill 0.2032)
		(layers "F.Cu" "B.Cu")
		(net "GND")
	)
	(via
		(at 176.896014 -266.1666)
		(size 0.4572)
		(drill 0.2032)
		(layers "F.Cu" "B.Cu")
		(net "GND")
	)
	(via
		(at 167.461946 -309.51678)
		(size 0.4572)
		(drill 0.2032)
		(layers "F.Cu" "B.Cu")
		(net "GND")
	)
	(via
		(at 190.093346 -279.766776)
		(size 0.4572)
		(drill 0.2032)
		(layers "F.Cu" "B.Cu")
		(net "GND")
	)
	(via
		(at 98.482912 -247.178322)
		(size 0.4572)
		(drill 0.2032)
		(layers "F.Cu" "B.Cu")
		(net "GND")
	)
	(via
		(at 164.901372 -128.086358)
		(size 0.508)
		(drill 0.254)
		(layers "F.Cu" "B.Cu")
		(net "GND")
	)
	(via
		(at 420.736014 -315.46673)
		(size 0.4572)
		(drill 0.2032)
		(layers "F.Cu" "B.Cu")
		(net "GND")
	)
	(via
		(at 165.808914 -406.980644)
		(size 0.4064)
		(drill 0.2032)
		(layers "F.Cu" "B.Cu")
		(net "GND")
	)
	(via
		(at 262.519414 -278.066754)
		(size 0.4572)
		(drill 0.2032)
		(layers "F.Cu" "B.Cu")
		(net "GND")
	)
	(via
		(at 274.163282 -238.116618)
		(size 0.4572)
		(drill 0.2032)
		(layers "F.Cu" "B.Cu")
		(net "GND")
	)
	(via
		(at 25.746964 -12.37488)
		(size 0.508)
		(drill 0.254)
		(layers "F.Cu" "B.Cu")
		(net "GND")
	)
	(via
		(at 109.760766 -222.761556)
		(size 0.4572)
		(drill 0.2032)
		(layers "F.Cu" "B.Cu")
		(net "GND")
	)
	(via
		(at 349.71228 -234.970066)
		(size 0.4572)
		(drill 0.2032)
		(layers "F.Cu" "B.Cu")
		(net "GND")
	)
	(via
		(at 2.764536 -300.150022)
		(size 0.508)
		(drill 0.254)
		(layers "F.Cu" "B.Cu")
		(net "GND")
	)
	(via
		(at 413.996886 -174.363126)
		(size 0.508)
		(drill 0.254)
		(layers "F.Cu" "B.Cu")
		(net "GND")
	)
	(via
		(at 136.258554 -410.030168)
		(size 0.4064)
		(drill 0.2032)
		(layers "F.Cu" "B.Cu")
		(net "GND")
	)
	(via
		(at 48.854614 -207.51673)
		(size 0.4572)
		(drill 0.2032)
		(layers "F.Cu" "B.Cu")
		(net "GND")
	)
	(via
		(at 199.527414 -204.116686)
		(size 0.4572)
		(drill 0.2032)
		(layers "F.Cu" "B.Cu")
		(net "GND")
	)
	(via
		(at 306.548282 -222.816674)
		(size 0.4572)
		(drill 0.2032)
		(layers "F.Cu" "B.Cu")
		(net "GND")
	)
	(via
		(at 327.83018 -409.396184)
		(size 0.4572)
		(drill 0.254)
		(layers "F.Cu" "B.Cu")
		(net "GND")
	)
	(via
		(at 52.298346 -258.516628)
		(size 0.4572)
		(drill 0.2032)
		(layers "F.Cu" "B.Cu")
		(net "GND")
	)
	(via
		(at 37.210746 -225.36658)
		(size 0.4572)
		(drill 0.2032)
		(layers "F.Cu" "B.Cu")
		(net "GND")
	)
	(via
		(at 61.84646 -5.842508)
		(size 0.508)
		(drill 0.254)
		(layers "F.Cu" "B.Cu")
		(net "GND")
	)
	(via
		(at 32.780732 -0.76454)
		(size 0.508)
		(drill 0.254)
		(layers "F.Cu" "B.Cu")
		(net "GND")
	)
	(via
		(at 22.123146 -276.366732)
		(size 0.4572)
		(drill 0.2032)
		(layers "F.Cu" "B.Cu")
		(net "GND")
	)
	(via
		(at 443.367414 -304.416714)
		(size 0.4572)
		(drill 0.2032)
		(layers "F.Cu" "B.Cu")
		(net "GND")
	)
	(via
		(at 435.823614 -285.716726)
		(size 0.4572)
		(drill 0.2032)
		(layers "F.Cu" "B.Cu")
		(net "GND")
	)
	(via
		(at 52.298346 -240.666778)
		(size 0.4572)
		(drill 0.2032)
		(layers "F.Cu" "B.Cu")
		(net "GND")
	)
	(via
		(at 159.918146 -261.916672)
		(size 0.4572)
		(drill 0.2032)
		(layers "F.Cu" "B.Cu")
		(net "GND")
	)
	(via
		(at 434.589682 -204.116686)
		(size 0.4572)
		(drill 0.2032)
		(layers "F.Cu" "B.Cu")
		(net "GND")
	)
	(via
		(at 412.355792 -360.687112)
		(size 0.508)
		(drill 0.254)
		(layers "F.Cu" "B.Cu")
		(net "GND")
	)
	(via
		(at 345.013534 -239.853216)
		(size 0.4572)
		(drill 0.2032)
		(layers "F.Cu" "B.Cu")
		(net "GND")
	)
	(via
		(at 279.816814 -273.816572)
		(size 0.4572)
		(drill 0.2032)
		(layers "F.Cu" "B.Cu")
		(net "GND")
	)
	(via
		(at 279.816814 -220.266768)
		(size 0.4572)
		(drill 0.2032)
		(layers "F.Cu" "B.Cu")
		(net "GND")
	)
	(via
		(at 129.54762 -19.916648)
		(size 0.508)
		(drill 0.254)
		(layers "F.Cu" "B.Cu")
		(net "GND")
	)
	(via
		(at 326.48398 -400.224244)
		(size 0.4572)
		(drill 0.254)
		(layers "F.Cu" "B.Cu")
		(net "GND")
	)
	(via
		(at 381.761238 -409.396184)
		(size 0.4572)
		(drill 0.254)
		(layers "F.Cu" "B.Cu")
		(net "GND")
	)
	(via
		(at 89.554812 -238.225584)
		(size 0.4572)
		(drill 0.2032)
		(layers "F.Cu" "B.Cu")
		(net "GND")
	)
	(via
		(at 52.911248 -154.97175)
		(size 0.49022)
		(drill 0.254)
		(layers "F.Cu" "B.Cu")
		(net "GND")
	)
	(via
		(at 373.207534 -244.73662)
		(size 0.4572)
		(drill 0.2032)
		(layers "F.Cu" "B.Cu")
		(net "GND")
	)
	(via
		(at 120.942354 -407.00452)
		(size 0.4064)
		(drill 0.2032)
		(layers "F.Cu" "B.Cu")
		(net "GND")
	)
	(via
		(at 412.355792 -360.026712)
		(size 0.508)
		(drill 0.254)
		(layers "F.Cu" "B.Cu")
		(net "GND")
	)
	(via
		(at 429.37684 -358.795066)
		(size 0.508)
		(drill 0.254)
		(layers "F.Cu" "B.Cu")
		(net "GND")
	)
	(via
		(at 434.589682 -261.066788)
		(size 0.4572)
		(drill 0.2032)
		(layers "F.Cu" "B.Cu")
		(net "GND")
	)
	(via
		(at 343.603834 -216.25052)
		(size 0.4572)
		(drill 0.2032)
		(layers "F.Cu" "B.Cu")
		(net "GND")
	)
	(via
		(at 385.534662 -272.639282)
		(size 0.4318)
		(drill 0.2032)
		(layers "F.Cu" "B.Cu")
		(net "GND")
	)
	(via
		(at 111.140748 -419.04158)
		(size 0.508)
		(drill 0.254)
		(layers "F.Cu" "B.Cu")
		(net "GND")
	)
	(via
		(at 29.666946 -216.016586)
		(size 0.4572)
		(drill 0.2032)
		(layers "F.Cu" "B.Cu")
		(net "GND")
	)
	(via
		(at 201.737214 -258.516628)
		(size 0.4572)
		(drill 0.2032)
		(layers "F.Cu" "B.Cu")
		(net "GND")
	)
	(via
		(at 270.063214 -306.116736)
		(size 0.4572)
		(drill 0.2032)
		(layers "F.Cu" "B.Cu")
		(net "GND")
	)
	(via
		(at 58.065162 -168.86428)
		(size 0.508)
		(drill 0.254)
		(layers "F.Cu" "B.Cu")
		(net "GND")
	)
	(via
		(at 179.105814 -216.866724)
		(size 0.4572)
		(drill 0.2032)
		(layers "F.Cu" "B.Cu")
		(net "GND")
	)
	(via
		(at 373.787162 -266.941808)
		(size 0.4572)
		(drill 0.2032)
		(layers "F.Cu" "B.Cu")
		(net "GND")
	)
	(via
		(at 300.238414 -272.116804)
		(size 0.4572)
		(drill 0.2032)
		(layers "F.Cu" "B.Cu")
		(net "GND")
	)
	(via
		(at 169.352214 -230.466646)
		(size 0.4572)
		(drill 0.2032)
		(layers "F.Cu" "B.Cu")
		(net "GND")
	)
	(via
		(at 386.474716 -262.872474)
		(size 0.4572)
		(drill 0.2032)
		(layers "F.Cu" "B.Cu")
		(net "GND")
	)
	(via
		(at 321.7037 -406.370536)
		(size 0.4572)
		(drill 0.254)
		(layers "F.Cu" "B.Cu")
		(net "GND")
	)
	(via
		(at 341.364062 -257.98907)
		(size 0.4572)
		(drill 0.2032)
		(layers "F.Cu" "B.Cu")
		(net "GND")
	)
	(via
		(at 176.896014 -286.56661)
		(size 0.4572)
		(drill 0.2032)
		(layers "F.Cu" "B.Cu")
		(net "GND")
	)
	(via
		(at 330.89342 -406.370536)
		(size 0.4572)
		(drill 0.254)
		(layers "F.Cu" "B.Cu")
		(net "GND")
	)
	(via
		(at 409.748482 -258.516628)
		(size 0.4572)
		(drill 0.2032)
		(layers "F.Cu" "B.Cu")
		(net "GND")
	)
	(via
		(at 165.252146 -244.916706)
		(size 0.4572)
		(drill 0.2032)
		(layers "F.Cu" "B.Cu")
		(net "GND")
	)
	(via
		(at 51.064414 -277.216616)
		(size 0.4572)
		(drill 0.2032)
		(layers "F.Cu" "B.Cu")
		(net "GND")
	)
	(via
		(at 413.022796 -285.65856)
		(size 0.4572)
		(drill 0.2032)
		(layers "F.Cu" "B.Cu")
		(net "GND")
	)
	(via
		(at 86.250018 -432.451256)
		(size 0.4572)
		(drill 0.2032)
		(layers "F.Cu" "B.Cu")
		(net "GND")
	)
	(via
		(at 56.050942 -16.978376)
		(size 0.508)
		(drill 0.254)
		(layers "F.Cu" "B.Cu")
		(net "GND")
	)
	(via
		(at 171.562014 -262.76681)
		(size 0.4572)
		(drill 0.2032)
		(layers "F.Cu" "B.Cu")
		(net "GND")
	)
	(via
		(at 191.983614 -198.166736)
		(size 0.4572)
		(drill 0.2032)
		(layers "F.Cu" "B.Cu")
		(net "GND")
	)
	(via
		(at 80.25003 -438.651396)
		(size 0.4572)
		(drill 0.2032)
		(layers "F.Cu" "B.Cu")
		(net "GND")
	)
	(via
		(at 160.412684 -21.596096)
		(size 0.508)
		(drill 0.254)
		(layers "F.Cu" "B.Cu")
		(net "GND")
	)
	(via
		(at 106.941366 -219.506038)
		(size 0.4572)
		(drill 0.2032)
		(layers "F.Cu" "B.Cu")
		(net "GND")
	)
	(via
		(at 257.185414 -206.666592)
		(size 0.4572)
		(drill 0.2032)
		(layers "F.Cu" "B.Cu")
		(net "GND")
	)
	(via
		(at 414.074356 -177.268378)
		(size 0.49022)
		(drill 0.254)
		(layers "F.Cu" "B.Cu")
		(net "GND")
	)
	(via
		(at 414.147762 -360.148378)
		(size 0.49022)
		(drill 0.254)
		(layers "F.Cu" "B.Cu")
		(net "GND")
	)
	(via
		(at 110.340394 -269.38351)
		(size 0.4572)
		(drill 0.2032)
		(layers "F.Cu" "B.Cu")
		(net "GND")
	)
	(via
		(at 46.964346 -210.916774)
		(size 0.4572)
		(drill 0.2032)
		(layers "F.Cu" "B.Cu")
		(net "GND")
	)
	(via
		(at 291.460682 -228.766624)
		(size 0.4572)
		(drill 0.2032)
		(layers "F.Cu" "B.Cu")
		(net "GND")
	)
	(via
		(at 22.123146 -233.016806)
		(size 0.4572)
		(drill 0.2032)
		(layers "F.Cu" "B.Cu")
		(net "GND")
	)
	(via
		(at 369.918234 -219.506038)
		(size 0.4572)
		(drill 0.2032)
		(layers "F.Cu" "B.Cu")
		(net "GND")
	)
	(via
		(at 153.99004 -41.059608)
		(size 0.508)
		(drill 0.254)
		(layers "F.Cu" "B.Cu")
		(net "GND")
	)
	(via
		(at 110.95736 -414.701228)
		(size 0.508)
		(drill 0.254)
		(layers "F.Cu" "B.Cu")
		(net "GND")
	)
	(via
		(at 370.028216 -275.08073)
		(size 0.4572)
		(drill 0.2032)
		(layers "F.Cu" "B.Cu")
		(net "GND")
	)
	(via
		(at 362.399834 -219.506038)
		(size 0.4572)
		(drill 0.2032)
		(layers "F.Cu" "B.Cu")
		(net "GND")
	)
	(via
		(at 264.729214 -240.666778)
		(size 0.4572)
		(drill 0.2032)
		(layers "F.Cu" "B.Cu")
		(net "GND")
	)
	(via
		(at 435.823614 -300.166786)
		(size 0.4572)
		(drill 0.2032)
		(layers "F.Cu" "B.Cu")
		(net "GND")
	)
	(via
		(at 294.904414 -248.31675)
		(size 0.4572)
		(drill 0.2032)
		(layers "F.Cu" "B.Cu")
		(net "GND")
	)
	(via
		(at 139.706096 -101.859842)
		(size 0.508)
		(drill 0.254)
		(layers "F.Cu" "B.Cu")
		(net "GND")
	)
	(via
		(at 339.014816 -268.569694)
		(size 0.4572)
		(drill 0.2032)
		(layers "F.Cu" "B.Cu")
		(net "GND")
	)
	(via
		(at 126.207266 -238.225584)
		(size 0.4572)
		(drill 0.2032)
		(layers "F.Cu" "B.Cu")
		(net "GND")
	)
	(via
		(at 31.876746 -210.916774)
		(size 0.4572)
		(drill 0.2032)
		(layers "F.Cu" "B.Cu")
		(net "GND")
	)
	(via
		(at 214.615014 -235.566712)
		(size 0.4572)
		(drill 0.2032)
		(layers "F.Cu" "B.Cu")
		(net "GND")
	)
	(via
		(at 88.144858 -216.25052)
		(size 0.4572)
		(drill 0.2032)
		(layers "F.Cu" "B.Cu")
		(net "GND")
	)
	(via
		(at 377.128532 -79.338424)
		(size 0.508)
		(drill 0.254)
		(layers "F.Cu" "B.Cu")
		(net "GND")
	)
	(via
		(at 14.01826 -91.658948)
		(size 0.508)
		(drill 0.254)
		(layers "F.Cu" "B.Cu")
		(net "GND")
	)
	(via
		(at 170.91533 -441.225432)
		(size 0.508)
		(drill 0.254)
		(layers "F.Cu" "B.Cu")
		(net "GND")
	)
	(via
		(at 262.519414 -246.616728)
		(size 0.4572)
		(drill 0.2032)
		(layers "F.Cu" "B.Cu")
		(net "GND")
	)
	(via
		(at 13.94968 -46.999906)
		(size 0.508)
		(drill 0.254)
		(layers "F.Cu" "B.Cu")
		(net "GND")
	)
	(via
		(at 191.983614 -215.166702)
		(size 0.4572)
		(drill 0.2032)
		(layers "F.Cu" "B.Cu")
		(net "GND")
	)
	(via
		(at 443.367414 -234.716574)
		(size 0.4572)
		(drill 0.2032)
		(layers "F.Cu" "B.Cu")
		(net "GND")
	)
	(via
		(at 22.123146 -281.466798)
		(size 0.4572)
		(drill 0.2032)
		(layers "F.Cu" "B.Cu")
		(net "GND")
	)
	(via
		(at 294.417496 -361.494324)
		(size 0.508)
		(drill 0.254)
		(layers "F.Cu" "B.Cu")
		(net "GND")
	)
	(via
		(at 97.653348 -273.453098)
		(size 0.4572)
		(drill 0.2032)
		(layers "F.Cu" "B.Cu")
		(net "GND")
	)
	(via
		(at 56.83885 -157.106874)
		(size 0.49022)
		(drill 0.254)
		(layers "F.Cu" "B.Cu")
		(net "GND")
	)
	(via
		(at 314.307982 -312.91657)
		(size 0.4572)
		(drill 0.2032)
		(layers "F.Cu" "B.Cu")
		(net "GND")
	)
	(via
		(at 458.455014 -208.366614)
		(size 0.4572)
		(drill 0.2032)
		(layers "F.Cu" "B.Cu")
		(net "GND")
	)
	(via
		(at 134.775448 -282.405836)
		(size 0.4572)
		(drill 0.2032)
		(layers "F.Cu" "B.Cu")
		(net "GND")
	)
	(via
		(at 84.250022 -430.299622)
		(size 0.4572)
		(drill 0.2032)
		(layers "F.Cu" "B.Cu")
		(net "GND")
	)
	(via
		(at 197.637146 -285.716726)
		(size 0.4572)
		(drill 0.2032)
		(layers "F.Cu" "B.Cu")
		(net "GND")
	)
	(via
		(at 309.992014 -234.716574)
		(size 0.4572)
		(drill 0.2032)
		(layers "F.Cu" "B.Cu")
		(net "GND")
	)
	(via
		(at 143.34998 -426.69968)
		(size 0.4572)
		(drill 0.2032)
		(layers "F.Cu" "B.Cu")
		(net "GND")
	)
	(via
		(at 334.785462 -264.50036)
		(size 0.4318)
		(drill 0.2032)
		(layers "F.Cu" "B.Cu")
		(net "GND")
	)
	(via
		(at 20.995894 -114.199416)
		(size 0.508)
		(drill 0.254)
		(layers "F.Cu" "B.Cu")
		(net "GND")
	)
	(via
		(at 190.093346 -217.716608)
		(size 0.4572)
		(drill 0.2032)
		(layers "F.Cu" "B.Cu")
		(net "GND")
	)
	(via
		(at 88.250014 -426.69968)
		(size 0.4572)
		(drill 0.2032)
		(layers "F.Cu" "B.Cu")
		(net "GND")
	)
	(via
		(at 114.39652 -26.580338)
		(size 0.508)
		(drill 0.254)
		(layers "F.Cu" "B.Cu")
		(net "GND")
	)
	(via
		(at 307.782214 -212.616796)
		(size 0.4572)
		(drill 0.2032)
		(layers "F.Cu" "B.Cu")
		(net "GND")
	)
	(via
		(at 458.455014 -260.21665)
		(size 0.4572)
		(drill 0.2032)
		(layers "F.Cu" "B.Cu")
		(net "GND")
	)
	(via
		(at 400.511772 -17.601438)
		(size 0.508)
		(drill 0.254)
		(layers "F.Cu" "B.Cu")
		(net "GND")
	)
	(via
		(at 455.011282 -291.666676)
		(size 0.4572)
		(drill 0.2032)
		(layers "F.Cu" "B.Cu")
		(net "GND")
	)
	(via
		(at 305.773328 -360.622088)
		(size 0.6604)
		(drill 0.3302)
		(layers "F.Cu" "B.Cu")
		(net "GND")
	)
	(via
		(at 430.489614 -278.066754)
		(size 0.4572)
		(drill 0.2032)
		(layers "F.Cu" "B.Cu")
		(net "GND")
	)
	(via
		(at 210.73872 -67.20332)
		(size 0.508)
		(drill 0.254)
		(layers "F.Cu" "B.Cu")
		(net "GND")
	)
	(via
		(at 300.238414 -229.616762)
		(size 0.4572)
		(drill 0.2032)
		(layers "F.Cu" "B.Cu")
		(net "GND")
	)
	(via
		(at 438.033414 -306.116736)
		(size 0.4572)
		(drill 0.2032)
		(layers "F.Cu" "B.Cu")
		(net "GND")
	)
	(via
		(at 90.20937 -409.396184)
		(size 0.4572)
		(drill 0.254)
		(layers "F.Cu" "B.Cu")
		(net "GND")
	)
	(via
		(at 169.352214 -245.76659)
		(size 0.4572)
		(drill 0.2032)
		(layers "F.Cu" "B.Cu")
		(net "GND")
	)
	(via
		(at 195.427346 -292.516814)
		(size 0.4572)
		(drill 0.2032)
		(layers "F.Cu" "B.Cu")
		(net "GND")
	)
	(via
		(at 126.317248 -282.405836)
		(size 0.4572)
		(drill 0.2032)
		(layers "F.Cu" "B.Cu")
		(net "GND")
	)
	(via
		(at 59.842146 -246.616728)
		(size 0.4572)
		(drill 0.2032)
		(layers "F.Cu" "B.Cu")
		(net "GND")
	)
	(via
		(at 314.092082 -264.466578)
		(size 0.4572)
		(drill 0.2032)
		(layers "F.Cu" "B.Cu")
		(net "GND")
	)
	(via
		(at 172.795946 -251.716794)
		(size 0.4572)
		(drill 0.2032)
		(layers "F.Cu" "B.Cu")
		(net "GND")
	)
	(via
		(at 339.014562 -266.941808)
		(size 0.4572)
		(drill 0.2032)
		(layers "F.Cu" "B.Cu")
		(net "GND")
	)
	(via
		(at 302.664114 -295.06672)
		(size 0.4572)
		(drill 0.2032)
		(layers "F.Cu" "B.Cu")
		(net "GND")
	)
	(via
		(at 124.327412 -239.853216)
		(size 0.4572)
		(drill 0.2032)
		(layers "F.Cu" "B.Cu")
		(net "GND")
	)
	(via
		(at 129.966212 -244.73662)
		(size 0.4572)
		(drill 0.2032)
		(layers "F.Cu" "B.Cu")
		(net "GND")
	)
	(via
		(at 285.150814 -220.266768)
		(size 0.4572)
		(drill 0.2032)
		(layers "F.Cu" "B.Cu")
		(net "GND")
	)
	(via
		(at 404.097998 -4.95173)
		(size 0.508)
		(drill 0.254)
		(layers "F.Cu" "B.Cu")
		(net "GND")
	)
	(via
		(at 254.27051 -78.643988)
		(size 0.508)
		(drill 0.254)
		(layers "F.Cu" "B.Cu")
		(net "GND")
	)
	(via
		(at 38.930834 -391.404094)
		(size 0.508)
		(drill 0.254)
		(layers "F.Cu" "B.Cu")
		(net "GND")
	)
	(via
		(at 455.444606 -69.461634)
		(size 0.508)
		(drill 0.254)
		(layers "F.Cu" "B.Cu")
		(net "GND")
	)
	(via
		(at 450.06641 -32.611822)
		(size 0.508)
		(drill 0.254)
		(layers "F.Cu" "B.Cu")
		(net "GND")
	)
	(via
		(at 160.817052 -75.378564)
		(size 0.508)
		(drill 0.254)
		(layers "F.Cu" "B.Cu")
		(net "GND")
	)
	(via
		(at 171.562014 -314.616592)
		(size 0.4572)
		(drill 0.2032)
		(layers "F.Cu" "B.Cu")
		(net "GND")
	)
	(via
		(at 121.978166 -237.411514)
		(size 0.4572)
		(drill 0.2032)
		(layers "F.Cu" "B.Cu")
		(net "GND")
	)
	(via
		(at 409.545282 -275.516594)
		(size 0.4572)
		(drill 0.2032)
		(layers "F.Cu" "B.Cu")
		(net "GND")
	)
	(via
		(at 56.049672 -155.125674)
		(size 0.49022)
		(drill 0.254)
		(layers "F.Cu" "B.Cu")
		(net "GND")
	)
	(via
		(at 455.011282 -262.76681)
		(size 0.4572)
		(drill 0.2032)
		(layers "F.Cu" "B.Cu")
		(net "GND")
	)
	(via
		(at 258.75488 -150.459948)
		(size 0.508)
		(drill 0.254)
		(layers "F.Cu" "B.Cu")
		(net "GND")
	)
	(via
		(at 371.797834 -226.017328)
		(size 0.4572)
		(drill 0.2032)
		(layers "F.Cu" "B.Cu")
		(net "GND")
	)
	(via
		(at 276.373082 -228.766624)
		(size 0.4572)
		(drill 0.2032)
		(layers "F.Cu" "B.Cu")
		(net "GND")
	)
	(via
		(at 439.923682 -301.01667)
		(size 0.4572)
		(drill 0.2032)
		(layers "F.Cu" "B.Cu")
		(net "GND")
	)
	(via
		(at 247.138444 -99.865434)
		(size 0.508)
		(drill 0.254)
		(layers "F.Cu" "B.Cu")
		(net "GND")
	)
	(via
		(at 291.460682 -275.516594)
		(size 0.4572)
		(drill 0.2032)
		(layers "F.Cu" "B.Cu")
		(net "GND")
	)
	(via
		(at 314.092082 -211.766658)
		(size 0.4572)
		(drill 0.2032)
		(layers "F.Cu" "B.Cu")
		(net "GND")
	)
	(via
		(at 28.433014 -278.916638)
		(size 0.4572)
		(drill 0.2032)
		(layers "F.Cu" "B.Cu")
		(net "GND")
	)
	(via
		(at 367.49482 -60.002928)
		(size 0.508)
		(drill 0.254)
		(layers "F.Cu" "B.Cu")
		(net "GND")
	)
	(via
		(at 62.737238 -400.858228)
		(size 0.4064)
		(drill 0.2032)
		(layers "F.Cu" "B.Cu")
		(net "GND")
	)
	(via
		(at 376.88774 -335.976214)
		(size 0.49022)
		(drill 0.254)
		(layers "F.Cu" "B.Cu")
		(net "GND")
	)
	(via
		(at 159.918146 -306.116736)
		(size 0.4572)
		(drill 0.2032)
		(layers "F.Cu" "B.Cu")
		(net "GND")
	)
	(via
		(at 412.989014 -276.366732)
		(size 0.4572)
		(drill 0.2032)
		(layers "F.Cu" "B.Cu")
		(net "GND")
	)
	(via
		(at 120.127014 -332.56601)
		(size 0.49022)
		(drill 0.254)
		(layers "F.Cu" "B.Cu")
		(net "GND")
	)
	(via
		(at 131.081526 -335.187036)
		(size 0.49022)
		(drill 0.254)
		(layers "F.Cu" "B.Cu")
		(net "GND")
	)
	(via
		(at 350.65208 -230.086662)
		(size 0.4572)
		(drill 0.2032)
		(layers "F.Cu" "B.Cu")
		(net "GND")
	)
	(via
		(at 289.250882 -297.616626)
		(size 0.4572)
		(drill 0.2032)
		(layers "F.Cu" "B.Cu")
		(net "GND")
	)
	(via
		(at 413.192214 -307.816758)
		(size 0.4572)
		(drill 0.2032)
		(layers "F.Cu" "B.Cu")
		(net "GND")
	)
	(via
		(at 214.615014 -269.566644)
		(size 0.4572)
		(drill 0.2032)
		(layers "F.Cu" "B.Cu")
		(net "GND")
	)
	(via
		(at 171.562014 -295.916604)
		(size 0.4572)
		(drill 0.2032)
		(layers "F.Cu" "B.Cu")
		(net "GND")
	)
	(via
		(at 56.398414 -222.816674)
		(size 0.4572)
		(drill 0.2032)
		(layers "F.Cu" "B.Cu")
		(net "GND")
	)
	(via
		(at 438.033414 -267.016738)
		(size 0.4572)
		(drill 0.2032)
		(layers "F.Cu" "B.Cu")
		(net "GND")
	)
	(via
		(at 134.775194 -285.661354)
		(size 0.4572)
		(drill 0.2032)
		(layers "F.Cu" "B.Cu")
		(net "GND")
	)
	(via
		(at 334.675734 -220.319854)
		(size 0.4318)
		(drill 0.2032)
		(layers "F.Cu" "B.Cu")
		(net "GND")
	)
	(via
		(at 50.379376 -354.109528)
		(size 0.49022)
		(drill 0.254)
		(layers "F.Cu" "B.Cu")
		(net "GND")
	)
	(via
		(at 302.664114 -208.366614)
		(size 0.4572)
		(drill 0.2032)
		(layers "F.Cu" "B.Cu")
		(net "GND")
	)
	(via
		(at 123.027694 -262.058658)
		(size 0.4572)
		(drill 0.2032)
		(layers "F.Cu" "B.Cu")
		(net "GND")
	)
	(via
		(at 411.349952 -435.0512)
		(size 0.4572)
		(drill 0.2032)
		(layers "F.Cu" "B.Cu")
		(net "GND")
	)
	(via
		(at 76.250038 -433.899564)
		(size 0.4572)
		(drill 0.2032)
		(layers "F.Cu" "B.Cu")
		(net "GND")
	)
	(via
		(at 65.25006 -431.29962)
		(size 0.4572)
		(drill 0.2032)
		(layers "F.Cu" "B.Cu")
		(net "GND")
	)
	(via
		(at 138.424666 -225.203258)
		(size 0.4572)
		(drill 0.2032)
		(layers "F.Cu" "B.Cu")
		(net "GND")
	)
	(via
		(at 413.454596 -16.967454)
		(size 0.508)
		(drill 0.254)
		(layers "F.Cu" "B.Cu")
		(net "GND")
	)
	(via
		(at 91.434412 -231.714548)
		(size 0.4572)
		(drill 0.2032)
		(layers "F.Cu" "B.Cu")
		(net "GND")
	)
	(via
		(at 20.889214 -291.666676)
		(size 0.4572)
		(drill 0.2032)
		(layers "F.Cu" "B.Cu")
		(net "GND")
	)
	(via
		(at 393.896596 -18.491454)
		(size 0.508)
		(drill 0.254)
		(layers "F.Cu" "B.Cu")
		(net "GND")
	)
	(via
		(at 111.170466 -230.086662)
		(size 0.4572)
		(drill 0.2032)
		(layers "F.Cu" "B.Cu")
		(net "GND")
	)
	(via
		(at 184.439814 -297.616626)
		(size 0.4572)
		(drill 0.2032)
		(layers "F.Cu" "B.Cu")
		(net "GND")
	)
	(via
		(at 41.310814 -202.416664)
		(size 0.4572)
		(drill 0.2032)
		(layers "F.Cu" "B.Cu")
		(net "GND")
	)
	(via
		(at 79.186532 -30.853126)
		(size 0.508)
		(drill 0.254)
		(layers "F.Cu" "B.Cu")
		(net "GND")
	)
	(via
		(at 336.085434 -234.15625)
		(size 0.4572)
		(drill 0.2032)
		(layers "F.Cu" "B.Cu")
		(net "GND")
	)
	(via
		(at 416.715702 -406.34666)
		(size 0.4572)
		(drill 0.254)
		(layers "F.Cu" "B.Cu")
		(net "GND")
	)
	(via
		(at 384.594862 -262.872474)
		(size 0.4572)
		(drill 0.2032)
		(layers "F.Cu" "B.Cu")
		(net "GND")
	)
	(via
		(at 73.54697 -400.224244)
		(size 0.4572)
		(drill 0.254)
		(layers "F.Cu" "B.Cu")
		(net "GND")
	)
	(via
		(at 422.945814 -290.816792)
		(size 0.4572)
		(drill 0.2032)
		(layers "F.Cu" "B.Cu")
		(net "GND")
	)
	(via
		(at 314.307982 -219.41663)
		(size 0.4572)
		(drill 0.2032)
		(layers "F.Cu" "B.Cu")
		(net "GND")
	)
	(via
		(at 58.725562 -160.22828)
		(size 0.508)
		(drill 0.254)
		(layers "F.Cu" "B.Cu")
		(net "GND")
	)
	(via
		(at 259.075682 -222.816674)
		(size 0.4572)
		(drill 0.2032)
		(layers "F.Cu" "B.Cu")
		(net "GND")
	)
	(via
		(at 58.824114 -314.616592)
		(size 0.4572)
		(drill 0.2032)
		(layers "F.Cu" "B.Cu")
		(net "GND")
	)
	(via
		(at 338.544916 -267.755878)
		(size 0.4572)
		(drill 0.2032)
		(layers "F.Cu" "B.Cu")
		(net "GND")
	)
	(via
		(at 417.292282 -271.266666)
		(size 0.4572)
		(drill 0.2032)
		(layers "F.Cu" "B.Cu")
		(net "GND")
	)
	(via
		(at 314.092082 -316.316614)
		(size 0.4572)
		(drill 0.2032)
		(layers "F.Cu" "B.Cu")
		(net "GND")
	)
	(via
		(at 98.592894 -289.807142)
		(size 0.4572)
		(drill 0.2032)
		(layers "F.Cu" "B.Cu")
		(net "GND")
	)
	(via
		(at 50.698908 -192.24117)
		(size 0.508)
		(drill 0.254)
		(layers "F.Cu" "B.Cu")
		(net "GND")
	)
	(via
		(at 335.725008 -288.917126)
		(size 0.4572)
		(drill 0.2032)
		(layers "F.Cu" "B.Cu")
		(net "GND")
	)
	(via
		(at 446.675002 -78.861412)
		(size 0.508)
		(drill 0.254)
		(layers "F.Cu" "B.Cu")
		(net "GND")
	)
	(via
		(at 59.842146 -317.166752)
		(size 0.4572)
		(drill 0.2032)
		(layers "F.Cu" "B.Cu")
		(net "GND")
	)
	(via
		(at 411.958282 -280.61666)
		(size 0.4572)
		(drill 0.2032)
		(layers "F.Cu" "B.Cu")
		(net "GND")
	)
	(via
		(at 41.310814 -216.866724)
		(size 0.4572)
		(drill 0.2032)
		(layers "F.Cu" "B.Cu")
		(net "GND")
	)
	(via
		(at 254.975614 -236.416596)
		(size 0.4572)
		(drill 0.2032)
		(layers "F.Cu" "B.Cu")
		(net "GND")
	)
	(via
		(at 87.331042 -339.114638)
		(size 0.49022)
		(drill 0.254)
		(layers "F.Cu" "B.Cu")
		(net "GND")
	)
	(via
		(at 358.295702 -295.038526)
		(size 0.508)
		(drill 0.254)
		(layers "F.Cu" "B.Cu")
		(net "GND")
	)
	(via
		(at 460.664814 -268.71676)
		(size 0.4572)
		(drill 0.2032)
		(layers "F.Cu" "B.Cu")
		(net "GND")
	)
	(via
		(at 447.467482 -241.516662)
		(size 0.4572)
		(drill 0.2032)
		(layers "F.Cu" "B.Cu")
		(net "GND")
	)
	(via
		(at 166.890954 -407.00452)
		(size 0.4064)
		(drill 0.2032)
		(layers "F.Cu" "B.Cu")
		(net "GND")
	)
	(via
		(at 113.287302 -332.56601)
		(size 0.49022)
		(drill 0.254)
		(layers "F.Cu" "B.Cu")
		(net "GND")
	)
	(via
		(at 113.46942 -97.137728)
		(size 0.508)
		(drill 0.254)
		(layers "F.Cu" "B.Cu")
		(net "GND")
	)
	(via
		(at 16.789146 -298.466764)
		(size 0.4572)
		(drill 0.2032)
		(layers "F.Cu" "B.Cu")
		(net "GND")
	)
	(via
		(at 340.894416 -270.19758)
		(size 0.4572)
		(drill 0.2032)
		(layers "F.Cu" "B.Cu")
		(net "GND")
	)
	(via
		(at 287.360614 -242.3668)
		(size 0.4572)
		(drill 0.2032)
		(layers "F.Cu" "B.Cu")
		(net "GND")
	)
	(via
		(at 207.071214 -310.366664)
		(size 0.4572)
		(drill 0.2032)
		(layers "F.Cu" "B.Cu")
		(net "GND")
	)
	(via
		(at 125.737112 -245.55069)
		(size 0.4572)
		(drill 0.2032)
		(layers "F.Cu" "B.Cu")
		(net "GND")
	)
	(via
		(at 53.002688 -5.596636)
		(size 0.508)
		(drill 0.254)
		(layers "F.Cu" "B.Cu")
		(net "GND")
	)
	(via
		(at 266.619482 -200.716642)
		(size 0.4572)
		(drill 0.2032)
		(layers "F.Cu" "B.Cu")
		(net "GND")
	)
	(via
		(at 26.223214 -205.816708)
		(size 0.4572)
		(drill 0.2032)
		(layers "F.Cu" "B.Cu")
		(net "GND")
	)
	(via
		(at 18.36801 -182.223156)
		(size 0.508)
		(drill 0.254)
		(layers "F.Cu" "B.Cu")
		(net "GND")
	)
	(via
		(at 358.42321 -358.848406)
		(size 0.508)
		(drill 0.254)
		(layers "F.Cu" "B.Cu")
		(net "GND")
	)
	(via
		(at 175.005746 -317.166752)
		(size 0.4572)
		(drill 0.2032)
		(layers "F.Cu" "B.Cu")
		(net "GND")
	)
	(via
		(at 209.281014 -312.91657)
		(size 0.4572)
		(drill 0.2032)
		(layers "F.Cu" "B.Cu")
		(net "GND")
	)
	(via
		(at 88.250014 -437.49976)
		(size 0.4572)
		(drill 0.2032)
		(layers "F.Cu" "B.Cu")
		(net "GND")
	)
	(via
		(at 87.785194 -274.266914)
		(size 0.4572)
		(drill 0.2032)
		(layers "F.Cu" "B.Cu")
		(net "GND")
	)
	(via
		(at 442.133482 -233.86669)
		(size 0.4572)
		(drill 0.2032)
		(layers "F.Cu" "B.Cu")
		(net "GND")
	)
	(via
		(at 111.812578 -335.704434)
		(size 0.49022)
		(drill 0.254)
		(layers "F.Cu" "B.Cu")
		(net "GND")
	)
	(via
		(at 447.467482 -247.466612)
		(size 0.4572)
		(drill 0.2032)
		(layers "F.Cu" "B.Cu")
		(net "GND")
	)
	(via
		(at 338.463128 -407.00452)
		(size 0.4064)
		(drill 0.2032)
		(layers "F.Cu" "B.Cu")
		(net "GND")
	)
	(via
		(at 427.045882 -314.616592)
		(size 0.4572)
		(drill 0.2032)
		(layers "F.Cu" "B.Cu")
		(net "GND")
	)
	(via
		(at 237.615984 -55.16499)
		(size 0.508)
		(drill 0.254)
		(layers "F.Cu" "B.Cu")
		(net "GND")
	)
	(via
		(at 331.351636 -404.51786)
		(size 0.4572)
		(drill 0.254)
		(layers "F.Cu" "B.Cu")
		(net "GND")
	)
	(via
		(at 207.071214 -222.816674)
		(size 0.4572)
		(drill 0.2032)
		(layers "F.Cu" "B.Cu")
		(net "GND")
	)
	(via
		(at 319.25006 -431.451258)
		(size 0.4572)
		(drill 0.2032)
		(layers "F.Cu" "B.Cu")
		(net "GND")
	)
	(via
		(at 97.183194 -287.28924)
		(size 0.4572)
		(drill 0.2032)
		(layers "F.Cu" "B.Cu")
		(net "GND")
	)
	(via
		(at 285.150814 -225.36658)
		(size 0.4572)
		(drill 0.2032)
		(layers "F.Cu" "B.Cu")
		(net "GND")
	)
	(via
		(at 386.474716 -257.98907)
		(size 0.4572)
		(drill 0.2032)
		(layers "F.Cu" "B.Cu")
		(net "GND")
	)
	(via
		(at 430.489614 -307.816758)
		(size 0.4572)
		(drill 0.2032)
		(layers "F.Cu" "B.Cu")
		(net "GND")
	)
	(via
		(at 167.525954 -403.883876)
		(size 0.4064)
		(drill 0.2032)
		(layers "F.Cu" "B.Cu")
		(net "GND")
	)
	(via
		(at 83.097878 -400.858228)
		(size 0.4064)
		(drill 0.2032)
		(layers "F.Cu" "B.Cu")
		(net "GND")
	)
	(via
		(at 380.725934 -243.108988)
		(size 0.4572)
		(drill 0.2032)
		(layers "F.Cu" "B.Cu")
		(net "GND")
	)
	(via
		(at 13.345414 -210.066636)
		(size 0.4572)
		(drill 0.2032)
		(layers "F.Cu" "B.Cu")
		(net "GND")
	)
	(via
		(at 175.57496 -351.414588)
		(size 0.508)
		(drill 0.254)
		(layers "F.Cu" "B.Cu")
		(net "GND")
	)
	(via
		(at 48.854614 -247.466612)
		(size 0.4572)
		(drill 0.2032)
		(layers "F.Cu" "B.Cu")
		(net "GND")
	)
	(via
		(at 294.904414 -199.01662)
		(size 0.4572)
		(drill 0.2032)
		(layers "F.Cu" "B.Cu")
		(net "GND")
	)
	(via
		(at 216.824814 -301.01667)
		(size 0.4572)
		(drill 0.2032)
		(layers "F.Cu" "B.Cu")
		(net "GND")
	)
	(via
		(at 386.364734 -217.064336)
		(size 0.4572)
		(drill 0.2032)
		(layers "F.Cu" "B.Cu")
		(net "GND")
	)
	(via
		(at 212.724746 -242.3668)
		(size 0.4572)
		(drill 0.2032)
		(layers "F.Cu" "B.Cu")
		(net "GND")
	)
	(via
		(at 431.61331 -133.478778)
		(size 0.508)
		(drill 0.254)
		(layers "F.Cu" "B.Cu")
		(net "GND")
	)
	(via
		(at 186.649614 -226.216718)
		(size 0.4572)
		(drill 0.2032)
		(layers "F.Cu" "B.Cu")
		(net "GND")
	)
	(via
		(at 420.09822 -152.933146)
		(size 0.49022)
		(drill 0.254)
		(layers "F.Cu" "B.Cu")
		(net "GND")
	)
	(via
		(at 79.760826 -409.396184)
		(size 0.4572)
		(drill 0.254)
		(layers "F.Cu" "B.Cu")
		(net "GND")
	)
	(via
		(at 127.616966 -239.0394)
		(size 0.4572)
		(drill 0.2032)
		(layers "F.Cu" "B.Cu")
		(net "GND")
	)
	(via
		(at 86.735666 -220.319854)
		(size 0.4318)
		(drill 0.2032)
		(layers "F.Cu" "B.Cu")
		(net "GND")
	)
	(via
		(at 450.911214 -295.06672)
		(size 0.4572)
		(drill 0.2032)
		(layers "F.Cu" "B.Cu")
		(net "GND")
	)
	(via
		(at 450.911214 -217.716608)
		(size 0.4572)
		(drill 0.2032)
		(layers "F.Cu" "B.Cu")
		(net "GND")
	)
	(via
		(at 79.760826 -410.664152)
		(size 0.4572)
		(drill 0.254)
		(layers "F.Cu" "B.Cu")
		(net "GND")
	)
	(via
		(at 60.551822 -160.22828)
		(size 0.508)
		(drill 0.254)
		(layers "F.Cu" "B.Cu")
		(net "GND")
	)
	(via
		(at 415.402014 -216.016586)
		(size 0.4572)
		(drill 0.2032)
		(layers "F.Cu" "B.Cu")
		(net "GND")
	)
	(via
		(at 25.746964 -10.16508)
		(size 0.508)
		(drill 0.254)
		(layers "F.Cu" "B.Cu")
		(net "GND")
	)
	(via
		(at 62.051946 -258.516628)
		(size 0.4572)
		(drill 0.2032)
		(layers "F.Cu" "B.Cu")
		(net "GND")
	)
	(via
		(at 159.56153 -45.317156)
		(size 0.508)
		(drill 0.254)
		(layers "F.Cu" "B.Cu")
		(net "GND")
	)
	(via
		(at 305.402488 -403.883876)
		(size 0.4064)
		(drill 0.2032)
		(layers "F.Cu" "B.Cu")
		(net "GND")
	)
	(via
		(at 202.971146 -301.866808)
		(size 0.4572)
		(drill 0.2032)
		(layers "F.Cu" "B.Cu")
		(net "GND")
	)
	(via
		(at 422.02354 -148.194268)
		(size 0.508)
		(drill 0.254)
		(layers "F.Cu" "B.Cu")
		(net "GND")
	)
	(via
		(at 259.075682 -244.066568)
		(size 0.4572)
		(drill 0.2032)
		(layers "F.Cu" "B.Cu")
		(net "GND")
	)
	(via
		(at 118.798594 -280.778204)
		(size 0.4572)
		(drill 0.2032)
		(layers "F.Cu" "B.Cu")
		(net "GND")
	)
	(via
		(at 139.956794 -400.858228)
		(size 0.4064)
		(drill 0.2032)
		(layers "F.Cu" "B.Cu")
		(net "GND")
	)
	(via
		(at 135.714994 -264.50036)
		(size 0.4572)
		(drill 0.2032)
		(layers "F.Cu" "B.Cu")
		(net "GND")
	)
	(via
		(at 447.467482 -194.766692)
		(size 0.4572)
		(drill 0.2032)
		(layers "F.Cu" "B.Cu")
		(net "GND")
	)
	(via
		(at 182.549546 -210.916774)
		(size 0.4572)
		(drill 0.2032)
		(layers "F.Cu" "B.Cu")
		(net "GND")
	)
	(via
		(at 43.520614 -250.866656)
		(size 0.4572)
		(drill 0.2032)
		(layers "F.Cu" "B.Cu")
		(net "GND")
	)
	(via
		(at 455.011282 -244.066568)
		(size 0.4572)
		(drill 0.2032)
		(layers "F.Cu" "B.Cu")
		(net "GND")
	)
	(via
		(at 432.379882 -215.166702)
		(size 0.4572)
		(drill 0.2032)
		(layers "F.Cu" "B.Cu")
		(net "GND")
	)
	(via
		(at 113.52022 -242.295172)
		(size 0.4572)
		(drill 0.2032)
		(layers "F.Cu" "B.Cu")
		(net "GND")
	)
	(via
		(at 380.445518 -78.485238)
		(size 0.6604)
		(drill 0.3302)
		(layers "F.Cu" "B.Cu")
		(net "GND")
	)
	(via
		(at 281.707082 -267.866622)
		(size 0.4572)
		(drill 0.2032)
		(layers "F.Cu" "B.Cu")
		(net "GND")
	)
	(via
		(at 176.896014 -224.516696)
		(size 0.4572)
		(drill 0.2032)
		(layers "F.Cu" "B.Cu")
		(net "GND")
	)
	(via
		(at 345.48318 -240.667286)
		(size 0.4572)
		(drill 0.2032)
		(layers "F.Cu" "B.Cu")
		(net "GND")
	)
	(via
		(at 214.615014 -284.866588)
		(size 0.4572)
		(drill 0.2032)
		(layers "F.Cu" "B.Cu")
		(net "GND")
	)
	(via
		(at 141.968982 -336.209132)
		(size 0.508)
		(drill 0.254)
		(layers "F.Cu" "B.Cu")
		(net "GND")
	)
	(via
		(at 43.85691 -7.215124)
		(size 0.508)
		(drill 0.254)
		(layers "F.Cu" "B.Cu")
		(net "GND")
	)
	(via
		(at 41.533572 -351.608644)
		(size 0.49022)
		(drill 0.254)
		(layers "F.Cu" "B.Cu")
		(net "GND")
	)
	(via
		(at 448.228212 -31.223458)
		(size 0.508)
		(drill 0.254)
		(layers "F.Cu" "B.Cu")
		(net "GND")
	)
	(via
		(at 407.48966 -61.587888)
		(size 0.508)
		(drill 0.254)
		(layers "F.Cu" "B.Cu")
		(net "GND")
	)
	(via
		(at 467.535514 -144.64538)
		(size 0.508)
		(drill 0.254)
		(layers "F.Cu" "B.Cu")
		(net "GND")
	)
	(via
		(at 180.211222 -354.115878)
		(size 0.49022)
		(drill 0.254)
		(layers "F.Cu" "B.Cu")
		(net "GND")
	)
	(via
		(at 311.882282 -269.566644)
		(size 0.4572)
		(drill 0.2032)
		(layers "F.Cu" "B.Cu")
		(net "GND")
	)
	(via
		(at 401.857718 -403.249892)
		(size 0.4572)
		(drill 0.254)
		(layers "F.Cu" "B.Cu")
		(net "GND")
	)
	(via
		(at 54.724046 -295.06672)
		(size 0.4572)
		(drill 0.2032)
		(layers "F.Cu" "B.Cu")
		(net "GND")
	)
	(via
		(at 373.317516 -262.872474)
		(size 0.4572)
		(drill 0.2032)
		(layers "F.Cu" "B.Cu")
		(net "GND")
	)
	(via
		(at 210.514946 -199.01662)
		(size 0.4572)
		(drill 0.2032)
		(layers "F.Cu" "B.Cu")
		(net "GND")
	)
	(via
		(at 406.54097 -403.883876)
		(size 0.4064)
		(drill 0.2032)
		(layers "F.Cu" "B.Cu")
		(net "GND")
	)
	(via
		(at 405.349964 -434.899562)
		(size 0.4572)
		(drill 0.2032)
		(layers "F.Cu" "B.Cu")
		(net "GND")
	)
	(via
		(at 381.961644 -336.823304)
		(size 0.508)
		(drill 0.254)
		(layers "F.Cu" "B.Cu")
		(net "GND")
	)
	(via
		(at 184.439814 -215.166702)
		(size 0.4572)
		(drill 0.2032)
		(layers "F.Cu" "B.Cu")
		(net "GND")
	)
	(via
		(at 190.093346 -273.816572)
		(size 0.4572)
		(drill 0.2032)
		(layers "F.Cu" "B.Cu")
		(net "GND")
	)
	(via
		(at 439.923682 -216.866724)
		(size 0.4572)
		(drill 0.2032)
		(layers "F.Cu" "B.Cu")
		(net "GND")
	)
	(via
		(at 207.071214 -239.81664)
		(size 0.4572)
		(drill 0.2032)
		(layers "F.Cu" "B.Cu")
		(net "GND")
	)
	(via
		(at 354.991416 -283.219906)
		(size 0.4572)
		(drill 0.2032)
		(layers "F.Cu" "B.Cu")
		(net "GND")
	)
	(via
		(at 369.427506 -173.370748)
		(size 0.508)
		(drill 0.254)
		(layers "F.Cu" "B.Cu")
		(net "GND")
	)
	(via
		(at 214.615014 -226.216718)
		(size 0.4572)
		(drill 0.2032)
		(layers "F.Cu" "B.Cu")
		(net "GND")
	)
	(via
		(at 135.605266 -247.992138)
		(size 0.4572)
		(drill 0.2032)
		(layers "F.Cu" "B.Cu")
		(net "GND")
	)
	(via
		(at 439.923682 -308.666642)
		(size 0.4572)
		(drill 0.2032)
		(layers "F.Cu" "B.Cu")
		(net "GND")
	)
	(via
		(at 424.836082 -194.766692)
		(size 0.4572)
		(drill 0.2032)
		(layers "F.Cu" "B.Cu")
		(net "GND")
	)
	(via
		(at 80.548226 -333.529432)
		(size 0.508)
		(drill 0.254)
		(layers "F.Cu" "B.Cu")
		(net "GND")
	)
	(via
		(at 375.547382 -400.224244)
		(size 0.4572)
		(drill 0.254)
		(layers "F.Cu" "B.Cu")
		(net "GND")
	)
	(via
		(at 409.748482 -249.166634)
		(size 0.4572)
		(drill 0.2032)
		(layers "F.Cu" "B.Cu")
		(net "GND")
	)
	(via
		(at 7.035546 -304.416714)
		(size 0.4572)
		(drill 0.2032)
		(layers "F.Cu" "B.Cu")
		(net "GND")
	)
	(via
		(at 349.917004 -65.764156)
		(size 0.508)
		(drill 0.254)
		(layers "F.Cu" "B.Cu")
		(net "GND")
	)
	(via
		(at 367.912904 -334.282034)
		(size 0.49022)
		(drill 0.254)
		(layers "F.Cu" "B.Cu")
		(net "GND")
	)
	(via
		(at 358.280462 -284.033722)
		(size 0.4572)
		(drill 0.2032)
		(layers "F.Cu" "B.Cu")
		(net "GND")
	)
	(via
		(at 137.014966 -248.806208)
		(size 0.4318)
		(drill 0.2032)
		(layers "F.Cu" "B.Cu")
		(net "GND")
	)
	(via
		(at 393.926822 -401.492212)
		(size 0.4572)
		(drill 0.254)
		(layers "F.Cu" "B.Cu")
		(net "GND")
	)
	(via
		(at 323.250052 -430.299622)
		(size 0.4572)
		(drill 0.2032)
		(layers "F.Cu" "B.Cu")
		(net "GND")
	)
	(via
		(at 363.368336 -255.805432)
		(size 0.4572)
		(drill 0.2032)
		(layers "F.Cu" "B.Cu")
		(net "GND")
	)
	(via
		(at 205.180946 -304.416714)
		(size 0.4572)
		(drill 0.2032)
		(layers "F.Cu" "B.Cu")
		(net "GND")
	)
	(via
		(at 121.038366 -226.017328)
		(size 0.4572)
		(drill 0.2032)
		(layers "F.Cu" "B.Cu")
		(net "GND")
	)
	(via
		(at 132.315966 -239.0394)
		(size 0.4572)
		(drill 0.2032)
		(layers "F.Cu" "B.Cu")
		(net "GND")
	)
	(via
		(at 389.146542 -407.638504)
		(size 0.4572)
		(drill 0.254)
		(layers "F.Cu" "B.Cu")
		(net "GND")
	)
	(via
		(at 376.96648 -228.45903)
		(size 0.4572)
		(drill 0.2032)
		(layers "F.Cu" "B.Cu")
		(net "GND")
	)
	(via
		(at 430.489614 -290.816792)
		(size 0.4572)
		(drill 0.2032)
		(layers "F.Cu" "B.Cu")
		(net "GND")
	)
	(via
		(at 108.820966 -216.25052)
		(size 0.4572)
		(drill 0.2032)
		(layers "F.Cu" "B.Cu")
		(net "GND")
	)
	(via
		(at 417.292282 -284.866588)
		(size 0.4572)
		(drill 0.2032)
		(layers "F.Cu" "B.Cu")
		(net "GND")
	)
	(via
		(at 428.279814 -251.716794)
		(size 0.4572)
		(drill 0.2032)
		(layers "F.Cu" "B.Cu")
		(net "GND")
	)
	(via
		(at 271.548352 -323.429376)
		(size 0.4572)
		(drill 0.2032)
		(layers "F.Cu" "B.Cu")
		(net "GND")
	)
	(via
		(at 383.020062 -409.396184)
		(size 0.4572)
		(drill 0.254)
		(layers "F.Cu" "B.Cu")
		(net "GND")
	)
	(via
		(at 11.135614 -278.916638)
		(size 0.4572)
		(drill 0.2032)
		(layers "F.Cu" "B.Cu")
		(net "GND")
	)
	(via
		(at 314.092082 -221.116652)
		(size 0.4572)
		(drill 0.2032)
		(layers "F.Cu" "B.Cu")
		(net "GND")
	)
	(via
		(at 54.333648 -146.33575)
		(size 0.49022)
		(drill 0.254)
		(layers "F.Cu" "B.Cu")
		(net "GND")
	)
	(via
		(at 370.563394 -295.038526)
		(size 0.508)
		(drill 0.254)
		(layers "F.Cu" "B.Cu")
		(net "GND")
	)
	(via
		(at 311.882282 -294.216582)
		(size 0.4572)
		(drill 0.2032)
		(layers "F.Cu" "B.Cu")
		(net "GND")
	)
	(via
		(at 51.064414 -284.866588)
		(size 0.4572)
		(drill 0.2032)
		(layers "F.Cu" "B.Cu")
		(net "GND")
	)
	(via
		(at 101.772212 -238.225584)
		(size 0.4572)
		(drill 0.2032)
		(layers "F.Cu" "B.Cu")
		(net "GND")
	)
	(via
		(at 35.976814 -205.816708)
		(size 0.4572)
		(drill 0.2032)
		(layers "F.Cu" "B.Cu")
		(net "GND")
	)
	(via
		(at 345.123516 -257.98907)
		(size 0.4572)
		(drill 0.2032)
		(layers "F.Cu" "B.Cu")
		(net "GND")
	)
	(via
		(at 218.958922 -73.671938)
		(size 0.508)
		(drill 0.254)
		(layers "F.Cu" "B.Cu")
		(net "GND")
	)
	(via
		(at 26.223214 -226.216718)
		(size 0.4572)
		(drill 0.2032)
		(layers "F.Cu" "B.Cu")
		(net "GND")
	)
	(via
		(at 100.472748 -270.19758)
		(size 0.4572)
		(drill 0.2032)
		(layers "F.Cu" "B.Cu")
		(net "GND")
	)
	(via
		(at 424.836082 -200.716642)
		(size 0.4572)
		(drill 0.2032)
		(layers "F.Cu" "B.Cu")
		(net "GND")
	)
	(via
		(at 427.045882 -244.066568)
		(size 0.4572)
		(drill 0.2032)
		(layers "F.Cu" "B.Cu")
		(net "GND")
	)
	(via
		(at 413.192214 -238.966756)
		(size 0.4572)
		(drill 0.2032)
		(layers "F.Cu" "B.Cu")
		(net "GND")
	)
	(via
		(at 355.931216 -268.569694)
		(size 0.4572)
		(drill 0.2032)
		(layers "F.Cu" "B.Cu")
		(net "GND")
	)
	(via
		(at 125.267466 -220.319854)
		(size 0.4572)
		(drill 0.2032)
		(layers "F.Cu" "B.Cu")
		(net "GND")
	)
	(via
		(at 98.123248 -259.616956)
		(size 0.4572)
		(drill 0.2032)
		(layers "F.Cu" "B.Cu")
		(net "GND")
	)
	(via
		(at 319.25006 -430.299622)
		(size 0.4572)
		(drill 0.2032)
		(layers "F.Cu" "B.Cu")
		(net "GND")
	)
	(via
		(at 113.52022 -235.783882)
		(size 0.4572)
		(drill 0.2032)
		(layers "F.Cu" "B.Cu")
		(net "GND")
	)
	(via
		(at 23.718266 -19.770344)
		(size 0.508)
		(drill 0.254)
		(layers "F.Cu" "B.Cu")
		(net "GND")
	)
	(via
		(at 116.449348 -283.219906)
		(size 0.4572)
		(drill 0.2032)
		(layers "F.Cu" "B.Cu")
		(net "GND")
	)
	(via
		(at 447.467482 -224.516696)
		(size 0.4572)
		(drill 0.2032)
		(layers "F.Cu" "B.Cu")
		(net "GND")
	)
	(via
		(at 194.193414 -305.266598)
		(size 0.4572)
		(drill 0.2032)
		(layers "F.Cu" "B.Cu")
		(net "GND")
	)
	(via
		(at 365.896144 -329.29957)
		(size 0.508)
		(drill 0.254)
		(layers "F.Cu" "B.Cu")
		(net "GND")
	)
	(via
		(at 39.420546 -265.316716)
		(size 0.4572)
		(drill 0.2032)
		(layers "F.Cu" "B.Cu")
		(net "GND")
	)
	(via
		(at 402.278596 -16.967454)
		(size 0.508)
		(drill 0.254)
		(layers "F.Cu" "B.Cu")
		(net "GND")
	)
	(via
		(at 413.192214 -216.016586)
		(size 0.4572)
		(drill 0.2032)
		(layers "F.Cu" "B.Cu")
		(net "GND")
	)
	(via
		(at 142.658846 -403.249892)
		(size 0.4572)
		(drill 0.254)
		(layers "F.Cu" "B.Cu")
		(net "GND")
	)
	(via
		(at 71.250048 -429.147224)
		(size 0.4572)
		(drill 0.2032)
		(layers "F.Cu" "B.Cu")
		(net "GND")
	)
	(via
		(at 46.964346 -265.316716)
		(size 0.4572)
		(drill 0.2032)
		(layers "F.Cu" "B.Cu")
		(net "GND")
	)
	(via
		(at 80.43037 -343.48293)
		(size 0.49022)
		(drill 0.254)
		(layers "F.Cu" "B.Cu")
		(net "GND")
	)
	(via
		(at 108.84154 -131.023868)
		(size 0.508)
		(drill 0.254)
		(layers "F.Cu" "B.Cu")
		(net "GND")
	)
	(via
		(at 375.27357 -407.00452)
		(size 0.4064)
		(drill 0.2032)
		(layers "F.Cu" "B.Cu")
		(net "GND")
	)
	(via
		(at 117.368066 -399.332958)
		(size 0.508)
		(drill 0.254)
		(layers "F.Cu" "B.Cu")
		(net "GND")
	)
	(via
		(at 356.373684 -252.659134)
		(size 0.4572)
		(drill 0.2032)
		(layers "F.Cu" "B.Cu")
		(net "GND")
	)
	(via
		(at 56.83885 -165.082474)
		(size 0.49022)
		(drill 0.254)
		(layers "F.Cu" "B.Cu")
		(net "GND")
	)
	(via
		(at 14.579346 -283.166566)
		(size 0.4572)
		(drill 0.2032)
		(layers "F.Cu" "B.Cu")
		(net "GND")
	)
	(via
		(at 435.823614 -216.016586)
		(size 0.4572)
		(drill 0.2032)
		(layers "F.Cu" "B.Cu")
		(net "GND")
	)
	(via
		(at 347.473016 -276.708616)
		(size 0.4572)
		(drill 0.2032)
		(layers "F.Cu" "B.Cu")
		(net "GND")
	)
	(via
		(at 138.34999 -427.851316)
		(size 0.4572)
		(drill 0.2032)
		(layers "F.Cu" "B.Cu")
		(net "GND")
	)
	(via
		(at 125.847348 -273.453098)
		(size 0.4572)
		(drill 0.2032)
		(layers "F.Cu" "B.Cu")
		(net "GND")
	)
	(via
		(at 130.350006 -438.651396)
		(size 0.4572)
		(drill 0.2032)
		(layers "F.Cu" "B.Cu")
		(net "GND")
	)
	(via
		(at 420.736014 -268.71676)
		(size 0.4572)
		(drill 0.2032)
		(layers "F.Cu" "B.Cu")
		(net "GND")
	)
	(via
		(at 193.432684 -323.434456)
		(size 0.4572)
		(drill 0.2032)
		(layers "F.Cu" "B.Cu")
		(net "GND")
	)
	(via
		(at 136.184894 -257.175254)
		(size 0.4572)
		(drill 0.2032)
		(layers "F.Cu" "B.Cu")
		(net "GND")
	)
	(via
		(at 209.281014 -216.866724)
		(size 0.4572)
		(drill 0.2032)
		(layers "F.Cu" "B.Cu")
		(net "GND")
	)
	(via
		(at 264.729214 -279.766776)
		(size 0.4572)
		(drill 0.2032)
		(layers "F.Cu" "B.Cu")
		(net "GND")
	)
	(via
		(at 61.250068 -428.851314)
		(size 0.4572)
		(drill 0.2032)
		(layers "F.Cu" "B.Cu")
		(net "GND")
	)
	(via
		(at 184.439814 -222.816674)
		(size 0.4572)
		(drill 0.2032)
		(layers "F.Cu" "B.Cu")
		(net "GND")
	)
	(via
		(at 389.604758 -400.200368)
		(size 0.4572)
		(drill 0.254)
		(layers "F.Cu" "B.Cu")
		(net "GND")
	)
	(via
		(at 320.083688 -410.030168)
		(size 0.4064)
		(drill 0.2032)
		(layers "F.Cu" "B.Cu")
		(net "GND")
	)
	(via
		(at 370.497862 -280.778204)
		(size 0.4572)
		(drill 0.2032)
		(layers "F.Cu" "B.Cu")
		(net "GND")
	)
	(via
		(at 361.569762 -258.80314)
		(size 0.4572)
		(drill 0.2032)
		(layers "F.Cu" "B.Cu")
		(net "GND")
	)
	(via
		(at 306.548282 -310.366664)
		(size 0.4572)
		(drill 0.2032)
		(layers "F.Cu" "B.Cu")
		(net "GND")
	)
	(via
		(at 65.25006 -427.699678)
		(size 0.4572)
		(drill 0.2032)
		(layers "F.Cu" "B.Cu")
		(net "GND")
	)
	(via
		(at 91.026742 -335.980278)
		(size 0.49022)
		(drill 0.254)
		(layers "F.Cu" "B.Cu")
		(net "GND")
	)
	(via
		(at 294.417496 -360.173524)
		(size 0.508)
		(drill 0.254)
		(layers "F.Cu" "B.Cu")
		(net "GND")
	)
	(via
		(at 190.093346 -295.06672)
		(size 0.4572)
		(drill 0.2032)
		(layers "F.Cu" "B.Cu")
		(net "GND")
	)
	(via
		(at 236.782356 -36.040314)
		(size 0.508)
		(drill 0.254)
		(layers "F.Cu" "B.Cu")
		(net "GND")
	)
	(via
		(at 14.579346 -220.266768)
		(size 0.4572)
		(drill 0.2032)
		(layers "F.Cu" "B.Cu")
		(net "GND")
	)
	(via
		(at 392.34999 -430.147222)
		(size 0.4572)
		(drill 0.2032)
		(layers "F.Cu" "B.Cu")
		(net "GND")
	)
	(via
		(at 37.940234 -108.555282)
		(size 0.508)
		(drill 0.254)
		(layers "F.Cu" "B.Cu")
		(net "GND")
	)
	(via
		(at 99.422966 -216.25052)
		(size 0.4572)
		(drill 0.2032)
		(layers "F.Cu" "B.Cu")
		(net "GND")
	)
	(via
		(at 336.034888 -403.883876)
		(size 0.4064)
		(drill 0.2032)
		(layers "F.Cu" "B.Cu")
		(net "GND")
	)
	(via
		(at 2.764536 -112.190022)
		(size 0.508)
		(drill 0.254)
		(layers "F.Cu" "B.Cu")
		(net "GND")
	)
	(via
		(at 337.299808 -48.050196)
		(size 0.4572)
		(drill 0.2032)
		(layers "F.Cu" "B.Cu")
		(net "GND")
	)
	(via
		(at 205.180946 -298.466764)
		(size 0.4572)
		(drill 0.2032)
		(layers "F.Cu" "B.Cu")
		(net "GND")
	)
	(via
		(at 315.927232 -29.675328)
		(size 0.508)
		(drill 0.254)
		(layers "F.Cu" "B.Cu")
		(net "GND")
	)
	(via
		(at 346.42298 -232.528364)
		(size 0.4572)
		(drill 0.2032)
		(layers "F.Cu" "B.Cu")
		(net "GND")
	)
	(via
		(at 305.128676 -407.638504)
		(size 0.4572)
		(drill 0.254)
		(layers "F.Cu" "B.Cu")
		(net "GND")
	)
	(via
		(at 40.495982 -6.597396)
		(size 0.508)
		(drill 0.254)
		(layers "F.Cu" "B.Cu")
		(net "GND")
	)
	(via
		(at 427.045882 -303.566576)
		(size 0.4572)
		(drill 0.2032)
		(layers "F.Cu" "B.Cu")
		(net "GND")
	)
	(via
		(at 280.050494 -19.929094)
		(size 0.508)
		(drill 0.254)
		(layers "F.Cu" "B.Cu")
		(net "GND")
	)
	(via
		(at 345.593162 -257.175254)
		(size 0.4572)
		(drill 0.2032)
		(layers "F.Cu" "B.Cu")
		(net "GND")
	)
	(via
		(at 323.250052 -437.49976)
		(size 0.4572)
		(drill 0.2032)
		(layers "F.Cu" "B.Cu")
		(net "GND")
	)
	(via
		(at 20.484846 -383.525776)
		(size 0.508)
		(drill 0.254)
		(layers "F.Cu" "B.Cu")
		(net "GND")
	)
	(via
		(at 171.8564 -219.41663)
		(size 0.4572)
		(drill 0.2032)
		(layers "F.Cu" "B.Cu")
		(net "GND")
	)
	(via
		(at 357.810562 -273.453098)
		(size 0.4572)
		(drill 0.2032)
		(layers "F.Cu" "B.Cu")
		(net "GND")
	)
	(via
		(at 155.349956 -425.547282)
		(size 0.4572)
		(drill 0.2032)
		(layers "F.Cu" "B.Cu")
		(net "GND")
	)
	(via
		(at 171.806362 -207.51673)
		(size 0.4572)
		(drill 0.2032)
		(layers "F.Cu" "B.Cu")
		(net "GND")
	)
	(via
		(at 197.637146 -217.716608)
		(size 0.4572)
		(drill 0.2032)
		(layers "F.Cu" "B.Cu")
		(net "GND")
	)
	(via
		(at 58.893456 -161.572702)
		(size 0.508)
		(drill 0.254)
		(layers "F.Cu" "B.Cu")
		(net "GND")
	)
	(via
		(at 42.046906 -18.502376)
		(size 0.508)
		(drill 0.254)
		(layers "F.Cu" "B.Cu")
		(net "GND")
	)
	(via
		(at 276.373082 -196.466714)
		(size 0.4572)
		(drill 0.2032)
		(layers "F.Cu" "B.Cu")
		(net "GND")
	)
	(via
		(at 300.238414 -214.316564)
		(size 0.4572)
		(drill 0.2032)
		(layers "F.Cu" "B.Cu")
		(net "GND")
	)
	(via
		(at 375.553986 -351.796858)
		(size 0.508)
		(drill 0.254)
		(layers "F.Cu" "B.Cu")
		(net "GND")
	)
	(via
		(at 102.712012 -231.714548)
		(size 0.4572)
		(drill 0.2032)
		(layers "F.Cu" "B.Cu")
		(net "GND")
	)
	(via
		(at 135.605266 -218.692222)
		(size 0.4572)
		(drill 0.2032)
		(layers "F.Cu" "B.Cu")
		(net "GND")
	)
	(via
		(at 199.527414 -233.86669)
		(size 0.4572)
		(drill 0.2032)
		(layers "F.Cu" "B.Cu")
		(net "GND")
	)
	(via
		(at 82.250026 -427.699678)
		(size 0.4572)
		(drill 0.2032)
		(layers "F.Cu" "B.Cu")
		(net "GND")
	)
	(via
		(at 173.826678 -188.55563)
		(size 0.508)
		(drill 0.254)
		(layers "F.Cu" "B.Cu")
		(net "GND")
	)
	(via
		(at 457.221082 -267.866622)
		(size 0.4572)
		(drill 0.2032)
		(layers "F.Cu" "B.Cu")
		(net "GND")
	)
	(via
		(at 427.045882 -232.166668)
		(size 0.4572)
		(drill 0.2032)
		(layers "F.Cu" "B.Cu")
		(net "GND")
	)
	(via
		(at 93.633798 -406.980644)
		(size 0.4064)
		(drill 0.2032)
		(layers "F.Cu" "B.Cu")
		(net "GND")
	)
	(via
		(at 289.250882 -258.516628)
		(size 0.4572)
		(drill 0.2032)
		(layers "F.Cu" "B.Cu")
		(net "GND")
	)
	(via
		(at 116.339366 -229.272846)
		(size 0.4572)
		(drill 0.2032)
		(layers "F.Cu" "B.Cu")
		(net "GND")
	)
	(via
		(at 404.462742 -409.396184)
		(size 0.4572)
		(drill 0.254)
		(layers "F.Cu" "B.Cu")
		(net "GND")
	)
	(via
		(at 109.620812 -338.47024)
		(size 0.508)
		(drill 0.254)
		(layers "F.Cu" "B.Cu")
		(net "GND")
	)
	(via
		(at 294.904414 -250.016772)
		(size 0.4572)
		(drill 0.2032)
		(layers "F.Cu" "B.Cu")
		(net "GND")
	)
	(via
		(at 434.589682 -241.516662)
		(size 0.4572)
		(drill 0.2032)
		(layers "F.Cu" "B.Cu")
		(net "GND")
	)
	(via
		(at 43.520614 -200.716642)
		(size 0.4572)
		(drill 0.2032)
		(layers "F.Cu" "B.Cu")
		(net "GND")
	)
	(via
		(at 291.460682 -261.066788)
		(size 0.4572)
		(drill 0.2032)
		(layers "F.Cu" "B.Cu")
		(net "GND")
	)
	(via
		(at 438.654952 -392.971274)
		(size 0.6604)
		(drill 0.3302)
		(layers "F.Cu" "B.Cu")
		(net "GND")
	)
	(via
		(at 450.88556 -59.637168)
		(size 0.508)
		(drill 0.254)
		(layers "F.Cu" "B.Cu")
		(net "GND")
	)
	(via
		(at 179.49672 -365.13389)
		(size 0.508)
		(drill 0.254)
		(layers "F.Cu" "B.Cu")
		(net "GND")
	)
	(via
		(at 338.434934 -244.73662)
		(size 0.4572)
		(drill 0.2032)
		(layers "F.Cu" "B.Cu")
		(net "GND")
	)
	(via
		(at 335.145634 -247.178322)
		(size 0.4572)
		(drill 0.2032)
		(layers "F.Cu" "B.Cu")
		(net "GND")
	)
	(via
		(at 210.514946 -296.766742)
		(size 0.4572)
		(drill 0.2032)
		(layers "F.Cu" "B.Cu")
		(net "GND")
	)
	(via
		(at 58.608214 -316.316614)
		(size 0.4572)
		(drill 0.2032)
		(layers "F.Cu" "B.Cu")
		(net "GND")
	)
	(via
		(at 360.050334 -226.831144)
		(size 0.4572)
		(drill 0.2032)
		(layers "F.Cu" "B.Cu")
		(net "GND")
	)
	(via
		(at 351.701862 -264.50036)
		(size 0.4572)
		(drill 0.2032)
		(layers "F.Cu" "B.Cu")
		(net "GND")
	)
	(via
		(at 51.467004 -9.424924)
		(size 0.508)
		(drill 0.254)
		(layers "F.Cu" "B.Cu")
		(net "GND")
	)
	(via
		(at 88.589358 -407.00452)
		(size 0.4064)
		(drill 0.2032)
		(layers "F.Cu" "B.Cu")
		(net "GND")
	)
	(via
		(at 417.292282 -232.166668)
		(size 0.4572)
		(drill 0.2032)
		(layers "F.Cu" "B.Cu")
		(net "GND")
	)
	(via
		(at 309.992014 -210.916774)
		(size 0.4572)
		(drill 0.2032)
		(layers "F.Cu" "B.Cu")
		(net "GND")
	)
	(via
		(at 333.213964 -441.225432)
		(size 0.508)
		(drill 0.254)
		(layers "F.Cu" "B.Cu")
		(net "GND")
	)
	(via
		(at 417.292282 -202.416664)
		(size 0.4572)
		(drill 0.2032)
		(layers "F.Cu" "B.Cu")
		(net "GND")
	)
	(via
		(at 409.748482 -280.61666)
		(size 0.4572)
		(drill 0.2032)
		(layers "F.Cu" "B.Cu")
		(net "GND")
	)
	(via
		(at 173.45406 -18.451068)
		(size 0.508)
		(drill 0.254)
		(layers "F.Cu" "B.Cu")
		(net "GND")
	)
	(via
		(at 161.808414 -295.916604)
		(size 0.4572)
		(drill 0.2032)
		(layers "F.Cu" "B.Cu")
		(net "GND")
	)
	(via
		(at 358.170734 -247.992138)
		(size 0.4572)
		(drill 0.2032)
		(layers "F.Cu" "B.Cu")
		(net "GND")
	)
	(via
		(at 287.01873 -76.615798)
		(size 0.508)
		(drill 0.254)
		(layers "F.Cu" "B.Cu")
		(net "GND")
	)
	(via
		(at 356.366064 -241.172492)
		(size 0.4572)
		(drill 0.2032)
		(layers "F.Cu" "B.Cu")
		(net "GND")
	)
	(via
		(at 417.292282 -303.566576)
		(size 0.4572)
		(drill 0.2032)
		(layers "F.Cu" "B.Cu")
		(net "GND")
	)
	(via
		(at 398.213072 -0.76454)
		(size 0.508)
		(drill 0.254)
		(layers "F.Cu" "B.Cu")
		(net "GND")
	)
	(via
		(at 9.245346 -300.166786)
		(size 0.4572)
		(drill 0.2032)
		(layers "F.Cu" "B.Cu")
		(net "GND")
	)
	(via
		(at 348.014036 -406.34666)
		(size 0.4572)
		(drill 0.254)
		(layers "F.Cu" "B.Cu")
		(net "GND")
	)
	(via
		(at 143.163036 -338.91601)
		(size 0.508)
		(drill 0.254)
		(layers "F.Cu" "B.Cu")
		(net "GND")
	)
	(via
		(at 100.942648 -275.8948)
		(size 0.4572)
		(drill 0.2032)
		(layers "F.Cu" "B.Cu")
		(net "GND")
	)
	(via
		(at 302.448214 -278.066754)
		(size 0.4572)
		(drill 0.2032)
		(layers "F.Cu" "B.Cu")
		(net "GND")
	)
	(via
		(at 361.45978 -216.25052)
		(size 0.4572)
		(drill 0.2032)
		(layers "F.Cu" "B.Cu")
		(net "GND")
	)
	(via
		(at 210.514946 -225.36658)
		(size 0.4572)
		(drill 0.2032)
		(layers "F.Cu" "B.Cu")
		(net "GND")
	)
	(via
		(at 128.35001 -432.451256)
		(size 0.4572)
		(drill 0.2032)
		(layers "F.Cu" "B.Cu")
		(net "GND")
	)
	(via
		(at 212.724746 -283.166566)
		(size 0.4572)
		(drill 0.2032)
		(layers "F.Cu" "B.Cu")
		(net "GND")
	)
	(via
		(at 467.535514 -109.08538)
		(size 0.508)
		(drill 0.254)
		(layers "F.Cu" "B.Cu")
		(net "GND")
	)
	(via
		(at 179.2224 -95.367348)
		(size 0.508)
		(drill 0.254)
		(layers "F.Cu" "B.Cu")
		(net "GND")
	)
	(via
		(at 377.076462 -259.616956)
		(size 0.4572)
		(drill 0.2032)
		(layers "F.Cu" "B.Cu")
		(net "GND")
	)
	(via
		(at 73.54697 -401.492212)
		(size 0.4572)
		(drill 0.254)
		(layers "F.Cu" "B.Cu")
		(net "GND")
	)
	(via
		(at 342.304116 -282.405836)
		(size 0.4572)
		(drill 0.2032)
		(layers "F.Cu" "B.Cu")
		(net "GND")
	)
	(via
		(at 373.677434 -226.017328)
		(size 0.4572)
		(drill 0.2032)
		(layers "F.Cu" "B.Cu")
		(net "GND")
	)
	(via
		(at 374.257062 -266.128246)
		(size 0.4572)
		(drill 0.2032)
		(layers "F.Cu" "B.Cu")
		(net "GND")
	)
	(via
		(at 91.544394 -271.011396)
		(size 0.4572)
		(drill 0.2032)
		(layers "F.Cu" "B.Cu")
		(net "GND")
	)
	(via
		(at 383.810764 -333.453232)
		(size 0.508)
		(drill 0.254)
		(layers "F.Cu" "B.Cu")
		(net "GND")
	)
	(via
		(at 458.455014 -301.866808)
		(size 0.4572)
		(drill 0.2032)
		(layers "F.Cu" "B.Cu")
		(net "GND")
	)
	(via
		(at 401.857718 -400.224244)
		(size 0.4572)
		(drill 0.254)
		(layers "F.Cu" "B.Cu")
		(net "GND")
	)
	(via
		(at 41.310814 -204.116686)
		(size 0.4572)
		(drill 0.2032)
		(layers "F.Cu" "B.Cu")
		(net "GND")
	)
	(via
		(at 364.383828 -331.924914)
		(size 0.508)
		(drill 0.254)
		(layers "F.Cu" "B.Cu")
		(net "GND")
	)
	(via
		(at 377.697238 -356.11181)
		(size 0.6604)
		(drill 0.3302)
		(layers "F.Cu" "B.Cu")
		(net "GND")
	)
	(via
		(at 134.665466 -218.692222)
		(size 0.4572)
		(drill 0.2032)
		(layers "F.Cu" "B.Cu")
		(net "GND")
	)
	(via
		(at 302.002444 -359.482898)
		(size 0.508)
		(drill 0.254)
		(layers "F.Cu" "B.Cu")
		(net "GND")
	)
	(via
		(at 342.774016 -276.708616)
		(size 0.4572)
		(drill 0.2032)
		(layers "F.Cu" "B.Cu")
		(net "GND")
	)
	(via
		(at 338.941156 -336.766662)
		(size 0.49022)
		(drill 0.254)
		(layers "F.Cu" "B.Cu")
		(net "GND")
	)
	(via
		(at 405.580596 -19.125438)
		(size 0.508)
		(drill 0.254)
		(layers "F.Cu" "B.Cu")
		(net "GND")
	)
	(via
		(at 394.28801 -403.883876)
		(size 0.4064)
		(drill 0.2032)
		(layers "F.Cu" "B.Cu")
		(net "GND")
	)
	(via
		(at 130.906266 -223.575626)
		(size 0.4572)
		(drill 0.2032)
		(layers "F.Cu" "B.Cu")
		(net "GND")
	)
	(via
		(at 35.976814 -241.516662)
		(size 0.4572)
		(drill 0.2032)
		(layers "F.Cu" "B.Cu")
		(net "GND")
	)
	(via
		(at 164.018214 -258.516628)
		(size 0.4572)
		(drill 0.2032)
		(layers "F.Cu" "B.Cu")
		(net "GND")
	)
	(via
		(at 373.787416 -258.80314)
		(size 0.4572)
		(drill 0.2032)
		(layers "F.Cu" "B.Cu")
		(net "GND")
	)
	(via
		(at 118.712488 -263.365996)
		(size 0.4572)
		(drill 0.2032)
		(layers "F.Cu" "B.Cu")
		(net "GND")
	)
	(via
		(at 48.82388 -103.800148)
		(size 0.508)
		(drill 0.254)
		(layers "F.Cu" "B.Cu")
		(net "GND")
	)
	(via
		(at 442.133482 -226.216718)
		(size 0.4572)
		(drill 0.2032)
		(layers "F.Cu" "B.Cu")
		(net "GND")
	)
	(via
		(at 259.075682 -294.216582)
		(size 0.4572)
		(drill 0.2032)
		(layers "F.Cu" "B.Cu")
		(net "GND")
	)
	(via
		(at 363.355636 -245.396512)
		(size 0.4572)
		(drill 0.2032)
		(layers "F.Cu" "B.Cu")
		(net "GND")
	)
	(via
		(at 343.603834 -226.017328)
		(size 0.4572)
		(drill 0.2032)
		(layers "F.Cu" "B.Cu")
		(net "GND")
	)
	(via
		(at 314.092082 -215.166702)
		(size 0.4572)
		(drill 0.2032)
		(layers "F.Cu" "B.Cu")
		(net "GND")
	)
	(via
		(at 175.603154 -350.093788)
		(size 0.508)
		(drill 0.254)
		(layers "F.Cu" "B.Cu")
		(net "GND")
	)
	(via
		(at 386.083302 -409.396184)
		(size 0.4572)
		(drill 0.254)
		(layers "F.Cu" "B.Cu")
		(net "GND")
	)
	(via
		(at 362.979462 -277.522432)
		(size 0.4572)
		(drill 0.2032)
		(layers "F.Cu" "B.Cu")
		(net "GND")
	)
	(via
		(at 88.255094 -258.80314)
		(size 0.4572)
		(drill 0.2032)
		(layers "F.Cu" "B.Cu")
		(net "GND")
	)
	(via
		(at 131.846066 -234.970066)
		(size 0.4572)
		(drill 0.2032)
		(layers "F.Cu" "B.Cu")
		(net "GND")
	)
	(via
		(at 5.127752 -406.246584)
		(size 0.508)
		(drill 0.254)
		(layers "F.Cu" "B.Cu")
		(net "GND")
	)
	(via
		(at 270.063214 -298.466764)
		(size 0.4572)
		(drill 0.2032)
		(layers "F.Cu" "B.Cu")
		(net "GND")
	)
	(via
		(at 186.649614 -261.066788)
		(size 0.4572)
		(drill 0.2032)
		(layers "F.Cu" "B.Cu")
		(net "GND")
	)
	(via
		(at 117.279166 -229.272846)
		(size 0.4572)
		(drill 0.2032)
		(layers "F.Cu" "B.Cu")
		(net "GND")
	)
	(via
		(at 367.568734 -223.575626)
		(size 0.4572)
		(drill 0.2032)
		(layers "F.Cu" "B.Cu")
		(net "GND")
	)
	(via
		(at 405.349964 -432.451256)
		(size 0.4572)
		(drill 0.2032)
		(layers "F.Cu" "B.Cu")
		(net "GND")
	)
	(via
		(at 35.976814 -303.566576)
		(size 0.4572)
		(drill 0.2032)
		(layers "F.Cu" "B.Cu")
		(net "GND")
	)
	(via
		(at 392.34999 -427.699678)
		(size 0.4572)
		(drill 0.2032)
		(layers "F.Cu" "B.Cu")
		(net "GND")
	)
	(via
		(at 121.287286 -326.859392)
		(size 0.508)
		(drill 0.254)
		(layers "F.Cu" "B.Cu")
		(net "GND")
	)
	(via
		(at 179.105814 -245.76659)
		(size 0.4572)
		(drill 0.2032)
		(layers "F.Cu" "B.Cu")
		(net "GND")
	)
	(via
		(at 129.026666 -236.597952)
		(size 0.4572)
		(drill 0.2032)
		(layers "F.Cu" "B.Cu")
		(net "GND")
	)
	(via
		(at 334.315562 -281.59202)
		(size 0.4572)
		(drill 0.2032)
		(layers "F.Cu" "B.Cu")
		(net "GND")
	)
	(via
		(at 342.304116 -279.150318)
		(size 0.4572)
		(drill 0.2032)
		(layers "F.Cu" "B.Cu")
		(net "GND")
	)
	(via
		(at 254.975614 -203.266802)
		(size 0.4572)
		(drill 0.2032)
		(layers "F.Cu" "B.Cu")
		(net "GND")
	)
	(via
		(at 122.557794 -266.128246)
		(size 0.4572)
		(drill 0.2032)
		(layers "F.Cu" "B.Cu")
		(net "GND")
	)
	(via
		(at 314.092082 -288.266632)
		(size 0.4572)
		(drill 0.2032)
		(layers "F.Cu" "B.Cu")
		(net "GND")
	)
	(via
		(at 317.250064 -438.499758)
		(size 0.4572)
		(drill 0.2032)
		(layers "F.Cu" "B.Cu")
		(net "GND")
	)
	(via
		(at 116.449348 -270.19758)
		(size 0.4572)
		(drill 0.2032)
		(layers "F.Cu" "B.Cu")
		(net "GND")
	)
	(via
		(at 18.679414 -294.216582)
		(size 0.4572)
		(drill 0.2032)
		(layers "F.Cu" "B.Cu")
		(net "GND")
	)
	(via
		(at 151.848566 -404.51786)
		(size 0.4572)
		(drill 0.254)
		(layers "F.Cu" "B.Cu")
		(net "GND")
	)
	(via
		(at 66.064638 -410.030168)
		(size 0.4064)
		(drill 0.2032)
		(layers "F.Cu" "B.Cu")
		(net "GND")
	)
	(via
		(at 257.185414 -195.616576)
		(size 0.4572)
		(drill 0.2032)
		(layers "F.Cu" "B.Cu")
		(net "GND")
	)
	(via
		(at 63.098426 -403.249892)
		(size 0.4572)
		(drill 0.254)
		(layers "F.Cu" "B.Cu")
		(net "GND")
	)
	(via
		(at 336.250026 -438.651396)
		(size 0.4572)
		(drill 0.2032)
		(layers "F.Cu" "B.Cu")
		(net "GND")
	)
	(via
		(at 270.063214 -195.616576)
		(size 0.4572)
		(drill 0.2032)
		(layers "F.Cu" "B.Cu")
		(net "GND")
	)
	(via
		(at 210.514946 -285.716726)
		(size 0.4572)
		(drill 0.2032)
		(layers "F.Cu" "B.Cu")
		(net "GND")
	)
	(via
		(at 362.814362 -401.670012)
		(size 0.508)
		(drill 0.254)
		(layers "F.Cu" "B.Cu")
		(net "GND")
	)
	(via
		(at 348.77248 -236.597952)
		(size 0.4572)
		(drill 0.2032)
		(layers "F.Cu" "B.Cu")
		(net "GND")
	)
	(via
		(at 186.649614 -213.46668)
		(size 0.4572)
		(drill 0.2032)
		(layers "F.Cu" "B.Cu")
		(net "GND")
	)
	(via
		(at 92.844366 -240.667286)
		(size 0.4572)
		(drill 0.2032)
		(layers "F.Cu" "B.Cu")
		(net "GND")
	)
	(via
		(at 439.923682 -282.316682)
		(size 0.4572)
		(drill 0.2032)
		(layers "F.Cu" "B.Cu")
		(net "GND")
	)
	(via
		(at 64.444626 -410.664152)
		(size 0.4572)
		(drill 0.254)
		(layers "F.Cu" "B.Cu")
		(net "GND")
	)
	(via
		(at 418.90188 -157.648148)
		(size 0.508)
		(drill 0.254)
		(layers "F.Cu" "B.Cu")
		(net "GND")
	)
	(via
		(at 339.209888 -43.751246)
		(size 0.4572)
		(drill 0.2032)
		(layers "F.Cu" "B.Cu")
		(net "GND")
	)
	(via
		(at 13.345414 -272.966688)
		(size 0.4572)
		(drill 0.2032)
		(layers "F.Cu" "B.Cu")
		(net "GND")
	)
	(via
		(at 123.387866 -213.732618)
		(size 0.4572)
		(drill 0.2032)
		(layers "F.Cu" "B.Cu")
		(net "GND")
	)
	(via
		(at 62.051946 -290.816792)
		(size 0.4572)
		(drill 0.2032)
		(layers "F.Cu" "B.Cu")
		(net "GND")
	)
	(via
		(at 175.005746 -285.716726)
		(size 0.4572)
		(drill 0.2032)
		(layers "F.Cu" "B.Cu")
		(net "GND")
	)
	(via
		(at 304.338482 -295.916604)
		(size 0.4572)
		(drill 0.2032)
		(layers "F.Cu" "B.Cu")
		(net "GND")
	)
	(via
		(at 340.894416 -278.336502)
		(size 0.4572)
		(drill 0.2032)
		(layers "F.Cu" "B.Cu")
		(net "GND")
	)
	(via
		(at 359.245916 -331.776832)
		(size 0.49022)
		(drill 0.254)
		(layers "F.Cu" "B.Cu")
		(net "GND")
	)
	(via
		(at 37.210746 -234.716574)
		(size 0.4572)
		(drill 0.2032)
		(layers "F.Cu" "B.Cu")
		(net "GND")
	)
	(via
		(at 380.25578 -230.900478)
		(size 0.4572)
		(drill 0.2032)
		(layers "F.Cu" "B.Cu")
		(net "GND")
	)
	(via
		(at 299.004482 -264.466578)
		(size 0.4572)
		(drill 0.2032)
		(layers "F.Cu" "B.Cu")
		(net "GND")
	)
	(via
		(at 384.124962 -253.919736)
		(size 0.4572)
		(drill 0.2032)
		(layers "F.Cu" "B.Cu")
		(net "GND")
	)
	(via
		(at 293.093902 -361.494324)
		(size 0.508)
		(drill 0.254)
		(layers "F.Cu" "B.Cu")
		(net "GND")
	)
	(via
		(at 354.003864 -250.337066)
		(size 0.4572)
		(drill 0.2032)
		(layers "F.Cu" "B.Cu")
		(net "GND")
	)
	(via
		(at 289.250882 -275.516594)
		(size 0.4572)
		(drill 0.2032)
		(layers "F.Cu" "B.Cu")
		(net "GND")
	)
	(via
		(at 47.21733 -391.089642)
		(size 0.508)
		(drill 0.254)
		(layers "F.Cu" "B.Cu")
		(net "GND")
	)
	(via
		(at 457.221082 -312.91657)
		(size 0.4572)
		(drill 0.2032)
		(layers "F.Cu" "B.Cu")
		(net "GND")
	)
	(via
		(at 306.548282 -316.316614)
		(size 0.4572)
		(drill 0.2032)
		(layers "F.Cu" "B.Cu")
		(net "GND")
	)
	(via
		(at 462.555082 -232.166668)
		(size 0.4572)
		(drill 0.2032)
		(layers "F.Cu" "B.Cu")
		(net "GND")
	)
	(via
		(at 306.764182 -238.116618)
		(size 0.4572)
		(drill 0.2032)
		(layers "F.Cu" "B.Cu")
		(net "GND")
	)
	(via
		(at 201.737214 -269.566644)
		(size 0.4572)
		(drill 0.2032)
		(layers "F.Cu" "B.Cu")
		(net "GND")
	)
	(via
		(at 48.854614 -272.966688)
		(size 0.4572)
		(drill 0.2032)
		(layers "F.Cu" "B.Cu")
		(net "GND")
	)
	(via
		(at 134.48792 -46.715934)
		(size 0.508)
		(drill 0.254)
		(layers "F.Cu" "B.Cu")
		(net "GND")
	)
	(via
		(at 63.942214 -286.56661)
		(size 0.4572)
		(drill 0.2032)
		(layers "F.Cu" "B.Cu")
		(net "GND")
	)
	(via
		(at 422.945814 -212.616796)
		(size 0.4572)
		(drill 0.2032)
		(layers "F.Cu" "B.Cu")
		(net "GND")
	)
	(via
		(at 266.619482 -316.316614)
		(size 0.4572)
		(drill 0.2032)
		(layers "F.Cu" "B.Cu")
		(net "GND")
	)
	(via
		(at 443.367414 -238.966756)
		(size 0.4572)
		(drill 0.2032)
		(layers "F.Cu" "B.Cu")
		(net "GND")
	)
	(via
		(at 210.514946 -298.466764)
		(size 0.4572)
		(drill 0.2032)
		(layers "F.Cu" "B.Cu")
		(net "GND")
	)
	(via
		(at 96.356678 -333.355188)
		(size 0.49022)
		(drill 0.254)
		(layers "F.Cu" "B.Cu")
		(net "GND")
	)
	(via
		(at 419.74643 -207.51673)
		(size 0.4572)
		(drill 0.2032)
		(layers "F.Cu" "B.Cu")
		(net "GND")
	)
	(via
		(at 62.64021 -406.370536)
		(size 0.4572)
		(drill 0.254)
		(layers "F.Cu" "B.Cu")
		(net "GND")
	)
	(via
		(at 450.911214 -223.666558)
		(size 0.4572)
		(drill 0.2032)
		(layers "F.Cu" "B.Cu")
		(net "GND")
	)
	(via
		(at 44.754546 -216.016586)
		(size 0.4572)
		(drill 0.2032)
		(layers "F.Cu" "B.Cu")
		(net "GND")
	)
	(via
		(at 54.792118 -18.246344)
		(size 0.508)
		(drill 0.254)
		(layers "F.Cu" "B.Cu")
		(net "GND")
	)
	(via
		(at 33.767014 -210.066636)
		(size 0.4572)
		(drill 0.2032)
		(layers "F.Cu" "B.Cu")
		(net "GND")
	)
	(via
		(at 54.508146 -267.016738)
		(size 0.4572)
		(drill 0.2032)
		(layers "F.Cu" "B.Cu")
		(net "GND")
	)
	(via
		(at 141.400022 -401.492212)
		(size 0.4572)
		(drill 0.254)
		(layers "F.Cu" "B.Cu")
		(net "GND")
	)
	(via
		(at 56.398414 -308.666642)
		(size 0.4572)
		(drill 0.2032)
		(layers "F.Cu" "B.Cu")
		(net "GND")
	)
	(via
		(at 356.761034 -230.900478)
		(size 0.4572)
		(drill 0.2032)
		(layers "F.Cu" "B.Cu")
		(net "GND")
	)
	(via
		(at 144.102074 -400.858228)
		(size 0.4064)
		(drill 0.2032)
		(layers "F.Cu" "B.Cu")
		(net "GND")
	)
	(via
		(at 373.247158 -177.66665)
		(size 0.508)
		(drill 0.254)
		(layers "F.Cu" "B.Cu")
		(net "GND")
	)
	(via
		(at 401.49653 -403.883876)
		(size 0.4064)
		(drill 0.2032)
		(layers "F.Cu" "B.Cu")
		(net "GND")
	)
	(via
		(at 58.893456 -144.300702)
		(size 0.508)
		(drill 0.254)
		(layers "F.Cu" "B.Cu")
		(net "GND")
	)
	(via
		(at 328.625708 -46.570646)
		(size 0.4572)
		(drill 0.2032)
		(layers "F.Cu" "B.Cu")
		(net "GND")
	)
	(via
		(at 31.147004 -10.16508)
		(size 0.508)
		(drill 0.254)
		(layers "F.Cu" "B.Cu")
		(net "GND")
	)
	(via
		(at 237.813342 -134.741412)
		(size 0.508)
		(drill 0.254)
		(layers "F.Cu" "B.Cu")
		(net "GND")
	)
	(via
		(at 411.47492 -156.261054)
		(size 0.508)
		(drill 0.254)
		(layers "F.Cu" "B.Cu")
		(net "GND")
	)
	(via
		(at 104.121966 -229.272846)
		(size 0.4572)
		(drill 0.2032)
		(layers "F.Cu" "B.Cu")
		(net "GND")
	)
	(via
		(at 86.250018 -430.147222)
		(size 0.4572)
		(drill 0.2032)
		(layers "F.Cu" "B.Cu")
		(net "GND")
	)
	(via
		(at 78.250034 -428.851314)
		(size 0.4572)
		(drill 0.2032)
		(layers "F.Cu" "B.Cu")
		(net "GND")
	)
	(via
		(at 140.349986 -432.451256)
		(size 0.4572)
		(drill 0.2032)
		(layers "F.Cu" "B.Cu")
		(net "GND")
	)
	(via
		(at 338.43468 -230.086662)
		(size 0.4572)
		(drill 0.2032)
		(layers "F.Cu" "B.Cu")
		(net "GND")
	)
	(via
		(at 171.795186 -238.116618)
		(size 0.4572)
		(drill 0.2032)
		(layers "F.Cu" "B.Cu")
		(net "GND")
	)
	(via
		(at 428.279814 -260.21665)
		(size 0.4572)
		(drill 0.2032)
		(layers "F.Cu" "B.Cu")
		(net "GND")
	)
	(via
		(at 89.555066 -220.319854)
		(size 0.4572)
		(drill 0.2032)
		(layers "F.Cu" "B.Cu")
		(net "GND")
	)
	(via
		(at 427.826424 -123.349512)
		(size 0.508)
		(drill 0.254)
		(layers "F.Cu" "B.Cu")
		(net "GND")
	)
	(via
		(at 325.176642 -65.237614)
		(size 0.508)
		(drill 0.254)
		(layers "F.Cu" "B.Cu")
		(net "GND")
	)
	(via
		(at 201.737214 -314.616592)
		(size 0.4572)
		(drill 0.2032)
		(layers "F.Cu" "B.Cu")
		(net "GND")
	)
	(via
		(at 54.3814 -173.831504)
		(size 0.508)
		(drill 0.254)
		(layers "F.Cu" "B.Cu")
		(net "GND")
	)
	(via
		(at 54.333648 -164.23767)
		(size 0.49022)
		(drill 0.254)
		(layers "F.Cu" "B.Cu")
		(net "GND")
	)
	(via
		(at 91.434666 -247.992138)
		(size 0.4572)
		(drill 0.2032)
		(layers "F.Cu" "B.Cu")
		(net "GND")
	)
	(via
		(at 276.373082 -202.416664)
		(size 0.4572)
		(drill 0.2032)
		(layers "F.Cu" "B.Cu")
		(net "GND")
	)
	(via
		(at 179.105814 -312.91657)
		(size 0.4572)
		(drill 0.2032)
		(layers "F.Cu" "B.Cu")
		(net "GND")
	)
	(via
		(at 210.75523 -126.512828)
		(size 0.508)
		(drill 0.254)
		(layers "F.Cu" "B.Cu")
		(net "GND")
	)
	(via
		(at 387.658864 -77.954886)
		(size 0.508)
		(drill 0.254)
		(layers "F.Cu" "B.Cu")
		(net "GND")
	)
	(via
		(at 7.035546 -267.016738)
		(size 0.4572)
		(drill 0.2032)
		(layers "F.Cu" "B.Cu")
		(net "GND")
	)
	(via
		(at 88.255094 -266.941808)
		(size 0.4572)
		(drill 0.2032)
		(layers "F.Cu" "B.Cu")
		(net "GND")
	)
	(via
		(at 138.34999 -436.347362)
		(size 0.4572)
		(drill 0.2032)
		(layers "F.Cu" "B.Cu")
		(net "GND")
	)
	(via
		(at 457.221082 -230.466646)
		(size 0.4572)
		(drill 0.2032)
		(layers "F.Cu" "B.Cu")
		(net "GND")
	)
	(via
		(at 307.782214 -195.616576)
		(size 0.4572)
		(drill 0.2032)
		(layers "F.Cu" "B.Cu")
		(net "GND")
	)
	(via
		(at 409.243022 -403.249892)
		(size 0.4572)
		(drill 0.254)
		(layers "F.Cu" "B.Cu")
		(net "GND")
	)
	(via
		(at 344.577162 -84.846922)
		(size 0.508)
		(drill 0.254)
		(layers "F.Cu" "B.Cu")
		(net "GND")
	)
	(via
		(at 427.045882 -278.916638)
		(size 0.4572)
		(drill 0.2032)
		(layers "F.Cu" "B.Cu")
		(net "GND")
	)
	(via
		(at 195.427346 -238.966756)
		(size 0.4572)
		(drill 0.2032)
		(layers "F.Cu" "B.Cu")
		(net "GND")
	)
	(via
		(at 13.345414 -278.916638)
		(size 0.4572)
		(drill 0.2032)
		(layers "F.Cu" "B.Cu")
		(net "GND")
	)
	(via
		(at 94.82328 -428.803308)
		(size 0.508)
		(drill 0.254)
		(layers "F.Cu" "B.Cu")
		(net "GND")
	)
	(via
		(at 407.858214 -251.716794)
		(size 0.4572)
		(drill 0.2032)
		(layers "F.Cu" "B.Cu")
		(net "GND")
	)
	(via
		(at 407.34996 -431.451258)
		(size 0.4572)
		(drill 0.2032)
		(layers "F.Cu" "B.Cu")
		(net "GND")
	)
	(via
		(at 309.992014 -203.266802)
		(size 0.4572)
		(drill 0.2032)
		(layers "F.Cu" "B.Cu")
		(net "GND")
	)
	(via
		(at 51.064414 -219.41663)
		(size 0.4572)
		(drill 0.2032)
		(layers "F.Cu" "B.Cu")
		(net "GND")
	)
	(via
		(at 439.923682 -294.216582)
		(size 0.4572)
		(drill 0.2032)
		(layers "F.Cu" "B.Cu")
		(net "GND")
	)
	(via
		(at 409.349956 -433.747164)
		(size 0.4572)
		(drill 0.2032)
		(layers "F.Cu" "B.Cu")
		(net "GND")
	)
	(via
		(at 39.420546 -317.166752)
		(size 0.4572)
		(drill 0.2032)
		(layers "F.Cu" "B.Cu")
		(net "GND")
	)
	(via
		(at 355.452426 -326.948292)
		(size 0.508)
		(drill 0.254)
		(layers "F.Cu" "B.Cu")
		(net "GND")
	)
	(via
		(at 377.546616 -262.058658)
		(size 0.4572)
		(drill 0.2032)
		(layers "F.Cu" "B.Cu")
		(net "GND")
	)
	(via
		(at 445.577214 -272.116804)
		(size 0.4572)
		(drill 0.2032)
		(layers "F.Cu" "B.Cu")
		(net "GND")
	)
	(via
		(at 161.808414 -244.066568)
		(size 0.4572)
		(drill 0.2032)
		(layers "F.Cu" "B.Cu")
		(net "GND")
	)
	(via
		(at 172.795946 -309.51678)
		(size 0.4572)
		(drill 0.2032)
		(layers "F.Cu" "B.Cu")
		(net "GND")
	)
	(via
		(at 139.956794 -403.883876)
		(size 0.4064)
		(drill 0.2032)
		(layers "F.Cu" "B.Cu")
		(net "GND")
	)
	(via
		(at 44.754546 -212.616796)
		(size 0.4572)
		(drill 0.2032)
		(layers "F.Cu" "B.Cu")
		(net "GND")
	)
	(via
		(at 74.990198 -400.858228)
		(size 0.4064)
		(drill 0.2032)
		(layers "F.Cu" "B.Cu")
		(net "GND")
	)
	(via
		(at 214.615014 -230.466646)
		(size 0.4572)
		(drill 0.2032)
		(layers "F.Cu" "B.Cu")
		(net "GND")
	)
	(via
		(at 352.334322 -178.995832)
		(size 0.508)
		(drill 0.254)
		(layers "F.Cu" "B.Cu")
		(net "GND")
	)
	(via
		(at 43.520614 -249.166634)
		(size 0.4572)
		(drill 0.2032)
		(layers "F.Cu" "B.Cu")
		(net "GND")
	)
	(via
		(at 340.250018 -426.69968)
		(size 0.4572)
		(drill 0.2032)
		(layers "F.Cu" "B.Cu")
		(net "GND")
	)
	(via
		(at 414.657286 -165.727126)
		(size 0.508)
		(drill 0.254)
		(layers "F.Cu" "B.Cu")
		(net "GND")
	)
	(via
		(at 411.958282 -316.316614)
		(size 0.4572)
		(drill 0.2032)
		(layers "F.Cu" "B.Cu")
		(net "GND")
	)
	(via
		(at 462.555082 -200.716642)
		(size 0.4572)
		(drill 0.2032)
		(layers "F.Cu" "B.Cu")
		(net "GND")
	)
	(via
		(at 432.379882 -288.266632)
		(size 0.4572)
		(drill 0.2032)
		(layers "F.Cu" "B.Cu")
		(net "GND")
	)
	(via
		(at 38.395402 -352.147378)
		(size 0.508)
		(drill 0.254)
		(layers "F.Cu" "B.Cu")
		(net "GND")
	)
	(via
		(at 201.737214 -272.966688)
		(size 0.4572)
		(drill 0.2032)
		(layers "F.Cu" "B.Cu")
		(net "GND")
	)
	(via
		(at 384.737102 -403.249892)
		(size 0.4572)
		(drill 0.254)
		(layers "F.Cu" "B.Cu")
		(net "GND")
	)
	(via
		(at 405.648414 -317.166752)
		(size 0.4572)
		(drill 0.2032)
		(layers "F.Cu" "B.Cu")
		(net "GND")
	)
	(via
		(at 372.377462 -279.150318)
		(size 0.4572)
		(drill 0.2032)
		(layers "F.Cu" "B.Cu")
		(net "GND")
	)
	(via
		(at 289.250882 -244.066568)
		(size 0.4572)
		(drill 0.2032)
		(layers "F.Cu" "B.Cu")
		(net "GND")
	)
	(via
		(at 190.093346 -214.316564)
		(size 0.4572)
		(drill 0.2032)
		(layers "F.Cu" "B.Cu")
		(net "GND")
	)
	(via
		(at 181.407308 -46.966886)
		(size 0.508)
		(drill 0.254)
		(layers "F.Cu" "B.Cu")
		(net "GND")
	)
	(via
		(at 175.005746 -214.316564)
		(size 0.4572)
		(drill 0.2032)
		(layers "F.Cu" "B.Cu")
		(net "GND")
	)
	(via
		(at 342.73363 -47.980092)
		(size 0.4572)
		(drill 0.2032)
		(layers "F.Cu" "B.Cu")
		(net "GND")
	)
	(via
		(at 302.448214 -216.016586)
		(size 0.4572)
		(drill 0.2032)
		(layers "F.Cu" "B.Cu")
		(net "GND")
	)
	(via
		(at 115.979194 -266.128246)
		(size 0.4572)
		(drill 0.2032)
		(layers "F.Cu" "B.Cu")
		(net "GND")
	)
	(via
		(at 347.363034 -219.506038)
		(size 0.4572)
		(drill 0.2032)
		(layers "F.Cu" "B.Cu")
		(net "GND")
	)
	(via
		(at 86.250018 -431.29962)
		(size 0.4572)
		(drill 0.2032)
		(layers "F.Cu" "B.Cu")
		(net "GND")
	)
	(via
		(at 370.498116 -262.872474)
		(size 0.4572)
		(drill 0.2032)
		(layers "F.Cu" "B.Cu")
		(net "GND")
	)
	(via
		(at 430.489614 -260.21665)
		(size 0.4572)
		(drill 0.2032)
		(layers "F.Cu" "B.Cu")
		(net "GND")
	)
	(via
		(at 384.594862 -272.639282)
		(size 0.4572)
		(drill 0.2032)
		(layers "F.Cu" "B.Cu")
		(net "GND")
	)
	(via
		(at 380.365762 -289.807142)
		(size 0.4572)
		(drill 0.2032)
		(layers "F.Cu" "B.Cu")
		(net "GND")
	)
	(via
		(at 368.038634 -219.506038)
		(size 0.4572)
		(drill 0.2032)
		(layers "F.Cu" "B.Cu")
		(net "GND")
	)
	(via
		(at 102.882192 -238.263684)
		(size 0.4572)
		(drill 0.2032)
		(layers "F.Cu" "B.Cu")
		(net "GND")
	)
	(via
		(at 207.071214 -205.816708)
		(size 0.4572)
		(drill 0.2032)
		(layers "F.Cu" "B.Cu")
		(net "GND")
	)
	(via
		(at 82.73669 -401.492212)
		(size 0.4572)
		(drill 0.254)
		(layers "F.Cu" "B.Cu")
		(net "GND")
	)
	(via
		(at 377.351798 -403.249892)
		(size 0.4572)
		(drill 0.254)
		(layers "F.Cu" "B.Cu")
		(net "GND")
	)
	(via
		(at 358.280462 -267.755878)
		(size 0.4572)
		(drill 0.2032)
		(layers "F.Cu" "B.Cu")
		(net "GND")
	)
	(via
		(at 331.069188 -43.751246)
		(size 0.4572)
		(drill 0.2032)
		(layers "F.Cu" "B.Cu")
		(net "GND")
	)
	(via
		(at 336.79638 -336.765392)
		(size 0.49022)
		(drill 0.254)
		(layers "F.Cu" "B.Cu")
		(net "GND")
	)
	(via
		(at 187.883546 -238.966756)
		(size 0.4572)
		(drill 0.2032)
		(layers "F.Cu" "B.Cu")
		(net "GND")
	)
	(via
		(at 205.180946 -278.066754)
		(size 0.4572)
		(drill 0.2032)
		(layers "F.Cu" "B.Cu")
		(net "GND")
	)
	(via
		(at 56.51373 -406.370536)
		(size 0.4572)
		(drill 0.254)
		(layers "F.Cu" "B.Cu")
		(net "GND")
	)
	(via
		(at 89.085166 -224.389442)
		(size 0.4572)
		(drill 0.2032)
		(layers "F.Cu" "B.Cu")
		(net "GND")
	)
	(via
		(at 197.429882 -81.506568)
		(size 0.508)
		(drill 0.254)
		(layers "F.Cu" "B.Cu")
		(net "GND")
	)
	(via
		(at 445.577214 -214.316564)
		(size 0.4572)
		(drill 0.2032)
		(layers "F.Cu" "B.Cu")
		(net "GND")
	)
	(via
		(at 270.063214 -304.416714)
		(size 0.4572)
		(drill 0.2032)
		(layers "F.Cu" "B.Cu")
		(net "GND")
	)
	(via
		(at 281.707082 -286.56661)
		(size 0.4572)
		(drill 0.2032)
		(layers "F.Cu" "B.Cu")
		(net "GND")
	)
	(via
		(at 277.607014 -220.266768)
		(size 0.4572)
		(drill 0.2032)
		(layers "F.Cu" "B.Cu")
		(net "GND")
	)
	(via
		(at 318.01816 -77.84592)
		(size 0.508)
		(drill 0.254)
		(layers "F.Cu" "B.Cu")
		(net "GND")
	)
	(via
		(at 146.083274 -400.858228)
		(size 0.4064)
		(drill 0.2032)
		(layers "F.Cu" "B.Cu")
		(net "GND")
	)
	(via
		(at 373.787416 -279.964134)
		(size 0.4572)
		(drill 0.2032)
		(layers "F.Cu" "B.Cu")
		(net "GND")
	)
	(via
		(at 292.694614 -298.466764)
		(size 0.4572)
		(drill 0.2032)
		(layers "F.Cu" "B.Cu")
		(net "GND")
	)
	(via
		(at 260.375908 -67.904868)
		(size 0.508)
		(drill 0.254)
		(layers "F.Cu" "B.Cu")
		(net "GND")
	)
	(via
		(at 358.280462 -262.872474)
		(size 0.4572)
		(drill 0.2032)
		(layers "F.Cu" "B.Cu")
		(net "GND")
	)
	(via
		(at 51.064414 -216.866724)
		(size 0.4572)
		(drill 0.2032)
		(layers "F.Cu" "B.Cu")
		(net "GND")
	)
	(via
		(at 311.882282 -291.666676)
		(size 0.4572)
		(drill 0.2032)
		(layers "F.Cu" "B.Cu")
		(net "GND")
	)
	(via
		(at 138.534394 -277.522432)
		(size 0.4572)
		(drill 0.2032)
		(layers "F.Cu" "B.Cu")
		(net "GND")
	)
	(via
		(at 136.545066 -230.086662)
		(size 0.4572)
		(drill 0.2032)
		(layers "F.Cu" "B.Cu")
		(net "GND")
	)
	(via
		(at 139.488418 -339.60435)
		(size 0.6604)
		(drill 0.3302)
		(layers "F.Cu" "B.Cu")
		(net "GND")
	)
	(via
		(at 287.360614 -248.31675)
		(size 0.4572)
		(drill 0.2032)
		(layers "F.Cu" "B.Cu")
		(net "GND")
	)
	(via
		(at 190.093346 -203.266802)
		(size 0.4572)
		(drill 0.2032)
		(layers "F.Cu" "B.Cu")
		(net "GND")
	)
	(via
		(at 135.135366 -247.178322)
		(size 0.4572)
		(drill 0.2032)
		(layers "F.Cu" "B.Cu")
		(net "GND")
	)
	(via
		(at 194.193414 -247.466612)
		(size 0.4572)
		(drill 0.2032)
		(layers "F.Cu" "B.Cu")
		(net "GND")
	)
	(via
		(at 108.461048 -274.266914)
		(size 0.4572)
		(drill 0.2032)
		(layers "F.Cu" "B.Cu")
		(net "GND")
	)
	(via
		(at 165.252146 -216.016586)
		(size 0.4572)
		(drill 0.2032)
		(layers "F.Cu" "B.Cu")
		(net "GND")
	)
	(via
		(at 344.183462 -277.522432)
		(size 0.4572)
		(drill 0.2032)
		(layers "F.Cu" "B.Cu")
		(net "GND")
	)
	(via
		(at 343.55024 -52.209446)
		(size 0.4572)
		(drill 0.2032)
		(layers "F.Cu" "B.Cu")
		(net "GND")
	)
	(via
		(at 304.338482 -269.566644)
		(size 0.4572)
		(drill 0.2032)
		(layers "F.Cu" "B.Cu")
		(net "GND")
	)
	(via
		(at 467.535514 -83.68538)
		(size 0.508)
		(drill 0.254)
		(layers "F.Cu" "B.Cu")
		(net "GND")
	)
	(via
		(at 87.78494 -275.8948)
		(size 0.4572)
		(drill 0.2032)
		(layers "F.Cu" "B.Cu")
		(net "GND")
	)
	(via
		(at 345.483434 -248.806208)
		(size 0.4572)
		(drill 0.2032)
		(layers "F.Cu" "B.Cu")
		(net "GND")
	)
	(via
		(at 341.724234 -227.64496)
		(size 0.4572)
		(drill 0.2032)
		(layers "F.Cu" "B.Cu")
		(net "GND")
	)
	(via
		(at 312.769758 -324.06717)
		(size 0.4572)
		(drill 0.2032)
		(layers "F.Cu" "B.Cu")
		(net "GND")
	)
	(via
		(at 13.345414 -245.76659)
		(size 0.4572)
		(drill 0.2032)
		(layers "F.Cu" "B.Cu")
		(net "GND")
	)
	(via
		(at 163.9189 -15.395448)
		(size 0.508)
		(drill 0.254)
		(layers "F.Cu" "B.Cu")
		(net "GND")
	)
	(via
		(at 172.795946 -283.166566)
		(size 0.4572)
		(drill 0.2032)
		(layers "F.Cu" "B.Cu")
		(net "GND")
	)
	(via
		(at 102.39502 -339.334602)
		(size 0.508)
		(drill 0.254)
		(layers "F.Cu" "B.Cu")
		(net "GND")
	)
	(via
		(at 455.011282 -205.816708)
		(size 0.4572)
		(drill 0.2032)
		(layers "F.Cu" "B.Cu")
		(net "GND")
	)
	(via
		(at 29.666946 -199.01662)
		(size 0.4572)
		(drill 0.2032)
		(layers "F.Cu" "B.Cu")
		(net "GND")
	)
	(via
		(at 157.701234 -410.030168)
		(size 0.4064)
		(drill 0.2032)
		(layers "F.Cu" "B.Cu")
		(net "GND")
	)
	(via
		(at 262.519414 -292.516814)
		(size 0.4572)
		(drill 0.2032)
		(layers "F.Cu" "B.Cu")
		(net "GND")
	)
	(via
		(at 411.958282 -275.516594)
		(size 0.4572)
		(drill 0.2032)
		(layers "F.Cu" "B.Cu")
		(net "GND")
	)
	(via
		(at 92.954348 -276.708616)
		(size 0.4572)
		(drill 0.2032)
		(layers "F.Cu" "B.Cu")
		(net "GND")
	)
	(via
		(at 199.527414 -271.266666)
		(size 0.4572)
		(drill 0.2032)
		(layers "F.Cu" "B.Cu")
		(net "GND")
	)
	(via
		(at 442.133482 -282.316682)
		(size 0.4572)
		(drill 0.2032)
		(layers "F.Cu" "B.Cu")
		(net "GND")
	)
	(via
		(at 401.76069 -410.030168)
		(size 0.4064)
		(drill 0.2032)
		(layers "F.Cu" "B.Cu")
		(net "GND")
	)
	(via
		(at 398.185386 -6.07949)
		(size 0.508)
		(drill 0.254)
		(layers "F.Cu" "B.Cu")
		(net "GND")
	)
	(via
		(at 182.549546 -317.166752)
		(size 0.4572)
		(drill 0.2032)
		(layers "F.Cu" "B.Cu")
		(net "GND")
	)
	(via
		(at 254.975614 -212.616796)
		(size 0.4572)
		(drill 0.2032)
		(layers "F.Cu" "B.Cu")
		(net "GND")
	)
	(via
		(at 125.737366 -219.506038)
		(size 0.4572)
		(drill 0.2032)
		(layers "F.Cu" "B.Cu")
		(net "GND")
	)
	(via
		(at 241.860832 -439.905394)
		(size 0.508)
		(drill 0.254)
		(layers "F.Cu" "B.Cu")
		(net "GND")
	)
	(via
		(at 385.064762 -258.80314)
		(size 0.4318)
		(drill 0.2032)
		(layers "F.Cu" "B.Cu")
		(net "GND")
	)
	(via
		(at 82.118454 -340.977728)
		(size 0.49022)
		(drill 0.254)
		(layers "F.Cu" "B.Cu")
		(net "GND")
	)
	(via
		(at 381.305816 -283.219906)
		(size 0.4572)
		(drill 0.2032)
		(layers "F.Cu" "B.Cu")
		(net "GND")
	)
	(via
		(at 298.21759 -364.759494)
		(size 0.49022)
		(drill 0.254)
		(layers "F.Cu" "B.Cu")
		(net "GND")
	)
	(via
		(at 169.352214 -200.716642)
		(size 0.4572)
		(drill 0.2032)
		(layers "F.Cu" "B.Cu")
		(net "GND")
	)
	(via
		(at 22.123146 -250.016772)
		(size 0.4572)
		(drill 0.2032)
		(layers "F.Cu" "B.Cu")
		(net "GND")
	)
	(via
		(at 58.608214 -204.116686)
		(size 0.4572)
		(drill 0.2032)
		(layers "F.Cu" "B.Cu")
		(net "GND")
	)
	(via
		(at 372.377462 -280.778204)
		(size 0.4572)
		(drill 0.2032)
		(layers "F.Cu" "B.Cu")
		(net "GND")
	)
	(via
		(at 363.80928 -231.714548)
		(size 0.4572)
		(drill 0.2032)
		(layers "F.Cu" "B.Cu")
		(net "GND")
	)
	(via
		(at 156.25699 -12.495022)
		(size 0.508)
		(drill 0.254)
		(layers "F.Cu" "B.Cu")
		(net "GND")
	)
	(via
		(at 283.916882 -210.066636)
		(size 0.4572)
		(drill 0.2032)
		(layers "F.Cu" "B.Cu")
		(net "GND")
	)
	(via
		(at 24.332946 -203.266802)
		(size 0.4572)
		(drill 0.2032)
		(layers "F.Cu" "B.Cu")
		(net "GND")
	)
	(via
		(at 94.253812 -247.992138)
		(size 0.4572)
		(drill 0.2032)
		(layers "F.Cu" "B.Cu")
		(net "GND")
	)
	(via
		(at 371.545358 -91.953334)
		(size 0.508)
		(drill 0.254)
		(layers "F.Cu" "B.Cu")
		(net "GND")
	)
	(via
		(at 66.152014 -232.166668)
		(size 0.4572)
		(drill 0.2032)
		(layers "F.Cu" "B.Cu")
		(net "GND")
	)
	(via
		(at 285.150814 -261.916672)
		(size 0.4572)
		(drill 0.2032)
		(layers "F.Cu" "B.Cu")
		(net "GND")
	)
	(via
		(at 7.035546 -208.366614)
		(size 0.4572)
		(drill 0.2032)
		(layers "F.Cu" "B.Cu")
		(net "GND")
	)
	(via
		(at 393.65301 -407.00452)
		(size 0.4064)
		(drill 0.2032)
		(layers "F.Cu" "B.Cu")
		(net "GND")
	)
	(via
		(at 9.245346 -268.71676)
		(size 0.4572)
		(drill 0.2032)
		(layers "F.Cu" "B.Cu")
		(net "GND")
	)
	(via
		(at 190.093346 -285.716726)
		(size 0.4572)
		(drill 0.2032)
		(layers "F.Cu" "B.Cu")
		(net "GND")
	)
	(via
		(at 294.904414 -216.016586)
		(size 0.4572)
		(drill 0.2032)
		(layers "F.Cu" "B.Cu")
		(net "GND")
	)
	(via
		(at 304.51552 -370.119148)
		(size 0.49022)
		(drill 0.254)
		(layers "F.Cu" "B.Cu")
		(net "GND")
	)
	(via
		(at 413.192214 -244.916706)
		(size 0.4572)
		(drill 0.2032)
		(layers "F.Cu" "B.Cu")
		(net "GND")
	)
	(via
		(at 46.964346 -306.116736)
		(size 0.4572)
		(drill 0.2032)
		(layers "F.Cu" "B.Cu")
		(net "GND")
	)
	(via
		(at 337.411822 -67.122548)
		(size 0.508)
		(drill 0.254)
		(layers "F.Cu" "B.Cu")
		(net "GND")
	)
	(via
		(at 18.679414 -224.516696)
		(size 0.4572)
		(drill 0.2032)
		(layers "F.Cu" "B.Cu")
		(net "GND")
	)
	(via
		(at 37.566854 -47.968408)
		(size 0.508)
		(drill 0.254)
		(layers "F.Cu" "B.Cu")
		(net "GND")
	)
	(via
		(at 96.243394 -256.361438)
		(size 0.4572)
		(drill 0.2032)
		(layers "F.Cu" "B.Cu")
		(net "GND")
	)
	(via
		(at 207.071214 -264.466578)
		(size 0.4572)
		(drill 0.2032)
		(layers "F.Cu" "B.Cu")
		(net "GND")
	)
	(via
		(at 132.895594 -271.011396)
		(size 0.4572)
		(drill 0.2032)
		(layers "F.Cu" "B.Cu")
		(net "GND")
	)
	(via
		(at 390.116568 -341.313516)
		(size 0.508)
		(drill 0.254)
		(layers "F.Cu" "B.Cu")
		(net "GND")
	)
	(via
		(at 187.883546 -289.11677)
		(size 0.4572)
		(drill 0.2032)
		(layers "F.Cu" "B.Cu")
		(net "GND")
	)
	(via
		(at 413.192214 -201.56678)
		(size 0.4572)
		(drill 0.2032)
		(layers "F.Cu" "B.Cu")
		(net "GND")
	)
	(via
		(at 132.425694 -289.807142)
		(size 0.4572)
		(drill 0.2032)
		(layers "F.Cu" "B.Cu")
		(net "GND")
	)
	(via
		(at 346.532962 -275.08073)
		(size 0.4572)
		(drill 0.2032)
		(layers "F.Cu" "B.Cu")
		(net "GND")
	)
	(via
		(at 138.34999 -435.0512)
		(size 0.4572)
		(drill 0.2032)
		(layers "F.Cu" "B.Cu")
		(net "GND")
	)
	(via
		(at 14.579346 -195.616576)
		(size 0.4572)
		(drill 0.2032)
		(layers "F.Cu" "B.Cu")
		(net "GND")
	)
	(via
		(at 419.502082 -211.766658)
		(size 0.4572)
		(drill 0.2032)
		(layers "F.Cu" "B.Cu")
		(net "GND")
	)
	(via
		(at 370.968016 -283.219906)
		(size 0.4572)
		(drill 0.2032)
		(layers "F.Cu" "B.Cu")
		(net "GND")
	)
	(via
		(at 110.230666 -223.575626)
		(size 0.4572)
		(drill 0.2032)
		(layers "F.Cu" "B.Cu")
		(net "GND")
	)
	(via
		(at 58.725562 -168.86428)
		(size 0.508)
		(drill 0.254)
		(layers "F.Cu" "B.Cu")
		(net "GND")
	)
	(via
		(at 109.657388 -292.95598)
		(size 0.508)
		(drill 0.254)
		(layers "F.Cu" "B.Cu")
		(net "GND")
	)
	(via
		(at 137.484866 -220.319854)
		(size 0.4572)
		(drill 0.2032)
		(layers "F.Cu" "B.Cu")
		(net "GND")
	)
	(via
		(at 210.514946 -246.616728)
		(size 0.4572)
		(drill 0.2032)
		(layers "F.Cu" "B.Cu")
		(net "GND")
	)
	(via
		(at 296.794682 -221.116652)
		(size 0.4572)
		(drill 0.2032)
		(layers "F.Cu" "B.Cu")
		(net "GND")
	)
	(via
		(at 52.217828 -432.020218)
		(size 0.508)
		(drill 0.254)
		(layers "F.Cu" "B.Cu")
		(net "GND")
	)
	(via
		(at 165.788848 -428.31385)
		(size 0.508)
		(drill 0.254)
		(layers "F.Cu" "B.Cu")
		(net "GND")
	)
	(via
		(at 444.119 -49.240948)
		(size 0.508)
		(drill 0.254)
		(layers "F.Cu" "B.Cu")
		(net "GND")
	)
	(via
		(at 312.51398 -407.638504)
		(size 0.4572)
		(drill 0.254)
		(layers "F.Cu" "B.Cu")
		(net "GND")
	)
	(via
		(at 335.761076 -407.638504)
		(size 0.4572)
		(drill 0.254)
		(layers "F.Cu" "B.Cu")
		(net "GND")
	)
	(via
		(at 75.351386 -403.249892)
		(size 0.4572)
		(drill 0.254)
		(layers "F.Cu" "B.Cu")
		(net "GND")
	)
	(via
		(at 14.579346 -221.96679)
		(size 0.4572)
		(drill 0.2032)
		(layers "F.Cu" "B.Cu")
		(net "GND")
	)
	(via
		(at 189.26302 -17.655032)
		(size 0.508)
		(drill 0.254)
		(layers "F.Cu" "B.Cu")
		(net "GND")
	)
	(via
		(at 51.064414 -207.51673)
		(size 0.4572)
		(drill 0.2032)
		(layers "F.Cu" "B.Cu")
		(net "GND")
	)
	(via
		(at 209.281014 -284.866588)
		(size 0.4572)
		(drill 0.2032)
		(layers "F.Cu" "B.Cu")
		(net "GND")
	)
	(via
		(at 457.221082 -205.816708)
		(size 0.4572)
		(drill 0.2032)
		(layers "F.Cu" "B.Cu")
		(net "GND")
	)
	(via
		(at 100.942394 -274.266914)
		(size 0.4572)
		(drill 0.2032)
		(layers "F.Cu" "B.Cu")
		(net "GND")
	)
	(via
		(at 103.761794 -264.50036)
		(size 0.4572)
		(drill 0.2032)
		(layers "F.Cu" "B.Cu")
		(net "GND")
	)
	(via
		(at 53.764942 -19.13636)
		(size 0.508)
		(drill 0.254)
		(layers "F.Cu" "B.Cu")
		(net "GND")
	)
	(via
		(at 25.327864 -398.241012)
		(size 0.508)
		(drill 0.254)
		(layers "F.Cu" "B.Cu")
		(net "GND")
	)
	(via
		(at 167.461946 -278.066754)
		(size 0.4572)
		(drill 0.2032)
		(layers "F.Cu" "B.Cu")
		(net "GND")
	)
	(via
		(at 384.48488 -236.597952)
		(size 0.4318)
		(drill 0.2032)
		(layers "F.Cu" "B.Cu")
		(net "GND")
	)
	(via
		(at 32.350964 -393.17549)
		(size 0.508)
		(drill 0.254)
		(layers "F.Cu" "B.Cu")
		(net "GND")
	)
	(via
		(at 371.437662 -282.405836)
		(size 0.4572)
		(drill 0.2032)
		(layers "F.Cu" "B.Cu")
		(net "GND")
	)
	(via
		(at 115.869466 -220.319854)
		(size 0.4572)
		(drill 0.2032)
		(layers "F.Cu" "B.Cu")
		(net "GND")
	)
	(via
		(at 146.941286 -67.343528)
		(size 0.508)
		(drill 0.254)
		(layers "F.Cu" "B.Cu")
		(net "GND")
	)
	(via
		(at 201.737214 -216.866724)
		(size 0.4572)
		(drill 0.2032)
		(layers "F.Cu" "B.Cu")
		(net "GND")
	)
	(via
		(at 175.005746 -220.266768)
		(size 0.4572)
		(drill 0.2032)
		(layers "F.Cu" "B.Cu")
		(net "GND")
	)
	(via
		(at 366.159034 -216.25052)
		(size 0.4572)
		(drill 0.2032)
		(layers "F.Cu" "B.Cu")
		(net "GND")
	)
	(via
		(at 434.844952 -388.73303)
		(size 0.508)
		(drill 0.254)
		(layers "F.Cu" "B.Cu")
		(net "GND")
	)
	(via
		(at 236.911896 -115.706652)
		(size 0.508)
		(drill 0.254)
		(layers "F.Cu" "B.Cu")
		(net "GND")
	)
	(via
		(at 289.250882 -216.866724)
		(size 0.4572)
		(drill 0.2032)
		(layers "F.Cu" "B.Cu")
		(net "GND")
	)
	(via
		(at 417.997894 -162.432238)
		(size 0.49022)
		(drill 0.254)
		(layers "F.Cu" "B.Cu")
		(net "GND")
	)
	(via
		(at 2.764536 -96.950022)
		(size 0.508)
		(drill 0.254)
		(layers "F.Cu" "B.Cu")
		(net "GND")
	)
	(via
		(at 114.4016 -86.058248)
		(size 0.508)
		(drill 0.254)
		(layers "F.Cu" "B.Cu")
		(net "GND")
	)
	(via
		(at 114.459766 -226.017328)
		(size 0.4572)
		(drill 0.2032)
		(layers "F.Cu" "B.Cu")
		(net "GND")
	)
	(via
		(at 7.79272 -111.288068)
		(size 0.508)
		(drill 0.254)
		(layers "F.Cu" "B.Cu")
		(net "GND")
	)
	(via
		(at 378.84608 -249.620024)
		(size 0.4572)
		(drill 0.2032)
		(layers "F.Cu" "B.Cu")
		(net "GND")
	)
	(via
		(at 164.292026 -216.866724)
		(size 0.4572)
		(drill 0.2032)
		(layers "F.Cu" "B.Cu")
		(net "GND")
	)
	(via
		(at 254.975614 -217.716608)
		(size 0.4572)
		(drill 0.2032)
		(layers "F.Cu" "B.Cu")
		(net "GND")
	)
	(via
		(at 415.298128 -49.831752)
		(size 0.508)
		(drill 0.254)
		(layers "F.Cu" "B.Cu")
		(net "GND")
	)
	(via
		(at 110.485682 -339.324696)
		(size 0.508)
		(drill 0.254)
		(layers "F.Cu" "B.Cu")
		(net "GND")
	)
	(via
		(at 79.760826 -406.370536)
		(size 0.4572)
		(drill 0.254)
		(layers "F.Cu" "B.Cu")
		(net "GND")
	)
	(via
		(at 63.001398 -407.00452)
		(size 0.4064)
		(drill 0.2032)
		(layers "F.Cu" "B.Cu")
		(net "GND")
	)
	(via
		(at 438.033414 -238.966756)
		(size 0.4572)
		(drill 0.2032)
		(layers "F.Cu" "B.Cu")
		(net "GND")
	)
	(via
		(at 86.265512 -217.878406)
		(size 0.4572)
		(drill 0.2032)
		(layers "F.Cu" "B.Cu")
		(net "GND")
	)
	(via
		(at 7.035546 -238.966756)
		(size 0.4572)
		(drill 0.2032)
		(layers "F.Cu" "B.Cu")
		(net "GND")
	)
	(via
		(at 438.23128 -7.153148)
		(size 0.508)
		(drill 0.254)
		(layers "F.Cu" "B.Cu")
		(net "GND")
	)
	(via
		(at 419.502082 -282.316682)
		(size 0.4572)
		(drill 0.2032)
		(layers "F.Cu" "B.Cu")
		(net "GND")
	)
	(via
		(at 87.13216 -31.120588)
		(size 0.508)
		(drill 0.254)
		(layers "F.Cu" "B.Cu")
		(net "GND")
	)
	(via
		(at 287.360614 -287.416748)
		(size 0.4572)
		(drill 0.2032)
		(layers "F.Cu" "B.Cu")
		(net "GND")
	)
	(via
		(at 274.163282 -295.916604)
		(size 0.4572)
		(drill 0.2032)
		(layers "F.Cu" "B.Cu")
		(net "GND")
	)
	(via
		(at 207.071214 -278.916638)
		(size 0.4572)
		(drill 0.2032)
		(layers "F.Cu" "B.Cu")
		(net "GND")
	)
	(via
		(at 261.285482 -198.166736)
		(size 0.4572)
		(drill 0.2032)
		(layers "F.Cu" "B.Cu")
		(net "GND")
	)
	(via
		(at 31.876746 -285.716726)
		(size 0.4572)
		(drill 0.2032)
		(layers "F.Cu" "B.Cu")
		(net "GND")
	)
	(via
		(at 167.461946 -212.616796)
		(size 0.4572)
		(drill 0.2032)
		(layers "F.Cu" "B.Cu")
		(net "GND")
	)
	(via
		(at 97.543366 -222.761556)
		(size 0.4572)
		(drill 0.2032)
		(layers "F.Cu" "B.Cu")
		(net "GND")
	)
	(via
		(at 136.68248 -117.636798)
		(size 0.508)
		(drill 0.254)
		(layers "F.Cu" "B.Cu")
		(net "GND")
	)
	(via
		(at 254.975614 -214.316564)
		(size 0.4572)
		(drill 0.2032)
		(layers "F.Cu" "B.Cu")
		(net "GND")
	)
	(via
		(at 447.467482 -277.216616)
		(size 0.4572)
		(drill 0.2032)
		(layers "F.Cu" "B.Cu")
		(net "GND")
	)
	(via
		(at 428.279814 -289.11677)
		(size 0.4572)
		(drill 0.2032)
		(layers "F.Cu" "B.Cu")
		(net "GND")
	)
	(via
		(at 270.063214 -216.016586)
		(size 0.4572)
		(drill 0.2032)
		(layers "F.Cu" "B.Cu")
		(net "GND")
	)
	(via
		(at 457.221082 -271.266666)
		(size 0.4572)
		(drill 0.2032)
		(layers "F.Cu" "B.Cu")
		(net "GND")
	)
	(via
		(at 199.527414 -310.366664)
		(size 0.4572)
		(drill 0.2032)
		(layers "F.Cu" "B.Cu")
		(net "GND")
	)
	(via
		(at 28.433014 -241.516662)
		(size 0.4572)
		(drill 0.2032)
		(layers "F.Cu" "B.Cu")
		(net "GND")
	)
	(via
		(at 52.191666 -410.664152)
		(size 0.4572)
		(drill 0.254)
		(layers "F.Cu" "B.Cu")
		(net "GND")
	)
	(via
		(at 196.14388 -134.711948)
		(size 0.508)
		(drill 0.254)
		(layers "F.Cu" "B.Cu")
		(net "GND")
	)
	(via
		(at 307.782214 -248.31675)
		(size 0.4572)
		(drill 0.2032)
		(layers "F.Cu" "B.Cu")
		(net "GND")
	)
	(via
		(at 22.123146 -220.266768)
		(size 0.4572)
		(drill 0.2032)
		(layers "F.Cu" "B.Cu")
		(net "GND")
	)
	(via
		(at 235.770674 -134.741666)
		(size 0.508)
		(drill 0.254)
		(layers "F.Cu" "B.Cu")
		(net "GND")
	)
	(via
		(at 393.313666 -179.346352)
		(size 0.508)
		(drill 0.254)
		(layers "F.Cu" "B.Cu")
		(net "GND")
	)
	(via
		(at 342.66378 -229.272846)
		(size 0.4572)
		(drill 0.2032)
		(layers "F.Cu" "B.Cu")
		(net "GND")
	)
	(via
		(at 39.40429 -319.312036)
		(size 0.4572)
		(drill 0.2032)
		(layers "F.Cu" "B.Cu")
		(net "GND")
	)
	(via
		(at 438.033414 -289.11677)
		(size 0.4572)
		(drill 0.2032)
		(layers "F.Cu" "B.Cu")
		(net "GND")
	)
	(via
		(at 332.144624 -338.303616)
		(size 0.508)
		(drill 0.254)
		(layers "F.Cu" "B.Cu")
		(net "GND")
	)
	(via
		(at 337.604862 -266.128246)
		(size 0.4572)
		(drill 0.2032)
		(layers "F.Cu" "B.Cu")
		(net "GND")
	)
	(via
		(at 169.352214 -308.666642)
		(size 0.4572)
		(drill 0.2032)
		(layers "F.Cu" "B.Cu")
		(net "GND")
	)
	(via
		(at 317.29426 -401.492212)
		(size 0.4572)
		(drill 0.254)
		(layers "F.Cu" "B.Cu")
		(net "GND")
	)
	(via
		(at 200.13295 -98.5266)
		(size 0.508)
		(drill 0.254)
		(layers "F.Cu" "B.Cu")
		(net "GND")
	)
	(via
		(at 56.364124 -177.327052)
		(size 0.508)
		(drill 0.254)
		(layers "F.Cu" "B.Cu")
		(net "GND")
	)
	(via
		(at 350.705674 -175.820832)
		(size 0.508)
		(drill 0.254)
		(layers "F.Cu" "B.Cu")
		(net "GND")
	)
	(via
		(at 407.446988 -7.215124)
		(size 0.508)
		(drill 0.254)
		(layers "F.Cu" "B.Cu")
		(net "GND")
	)
	(via
		(at 47.811182 -350.323658)
		(size 0.508)
		(drill 0.254)
		(layers "F.Cu" "B.Cu")
		(net "GND")
	)
	(via
		(at 345.224608 -400.858228)
		(size 0.4064)
		(drill 0.2032)
		(layers "F.Cu" "B.Cu")
		(net "GND")
	)
	(via
		(at 364.383828 -330.604114)
		(size 0.508)
		(drill 0.254)
		(layers "F.Cu" "B.Cu")
		(net "GND")
	)
	(via
		(at 284.778196 -360.714544)
		(size 0.508)
		(drill 0.254)
		(layers "F.Cu" "B.Cu")
		(net "GND")
	)
	(via
		(at 82.250026 -431.29962)
		(size 0.4572)
		(drill 0.2032)
		(layers "F.Cu" "B.Cu")
		(net "GND")
	)
	(via
		(at 414.863534 -168.632378)
		(size 0.49022)
		(drill 0.254)
		(layers "F.Cu" "B.Cu")
		(net "GND")
	)
	(via
		(at 344.903552 -37.056822)
		(size 0.49022)
		(drill 0.254)
		(layers "F.Cu" "B.Cu")
		(net "GND")
	)
	(via
		(at 329.634596 -407.638504)
		(size 0.4572)
		(drill 0.254)
		(layers "F.Cu" "B.Cu")
		(net "GND")
	)
	(via
		(at 312.972196 -403.249892)
		(size 0.4572)
		(drill 0.254)
		(layers "F.Cu" "B.Cu")
		(net "GND")
	)
	(via
		(at 257.185414 -234.716574)
		(size 0.4572)
		(drill 0.2032)
		(layers "F.Cu" "B.Cu")
		(net "GND")
	)
	(via
		(at 414.16478 -167.071548)
		(size 0.508)
		(drill 0.254)
		(layers "F.Cu" "B.Cu")
		(net "GND")
	)
	(via
		(at 424.836082 -288.266632)
		(size 0.4572)
		(drill 0.2032)
		(layers "F.Cu" "B.Cu")
		(net "GND")
	)
	(via
		(at 119.158766 -216.25052)
		(size 0.4572)
		(drill 0.2032)
		(layers "F.Cu" "B.Cu")
		(net "GND")
	)
	(via
		(at 283.916882 -261.066788)
		(size 0.4572)
		(drill 0.2032)
		(layers "F.Cu" "B.Cu")
		(net "GND")
	)
	(via
		(at 29.78277 -439.527188)
		(size 0.508)
		(drill 0.254)
		(layers "F.Cu" "B.Cu")
		(net "GND")
	)
	(via
		(at 37.210746 -296.766742)
		(size 0.4572)
		(drill 0.2032)
		(layers "F.Cu" "B.Cu")
		(net "GND")
	)
	(via
		(at 128.688846 -410.664152)
		(size 0.4572)
		(drill 0.254)
		(layers "F.Cu" "B.Cu")
		(net "GND")
	)
	(via
		(at 334.675734 -231.714548)
		(size 0.4318)
		(drill 0.2032)
		(layers "F.Cu" "B.Cu")
		(net "GND")
	)
	(via
		(at 375.04878 -421.125396)
		(size 0.508)
		(drill 0.254)
		(layers "F.Cu" "B.Cu")
		(net "GND")
	)
	(via
		(at 61.250068 -439.651394)
		(size 0.4572)
		(drill 0.2032)
		(layers "F.Cu" "B.Cu")
		(net "GND")
	)
	(via
		(at 431.24628 -361.598464)
		(size 0.508)
		(drill 0.254)
		(layers "F.Cu" "B.Cu")
		(net "GND")
	)
	(via
		(at 373.677434 -248.806208)
		(size 0.4572)
		(drill 0.2032)
		(layers "F.Cu" "B.Cu")
		(net "GND")
	)
	(via
		(at 426.821854 -183.428132)
		(size 0.508)
		(drill 0.254)
		(layers "F.Cu" "B.Cu")
		(net "GND")
	)
	(via
		(at 414.85947 -170.853354)
		(size 0.49022)
		(drill 0.254)
		(layers "F.Cu" "B.Cu")
		(net "GND")
	)
	(via
		(at 216.824814 -194.766692)
		(size 0.4572)
		(drill 0.2032)
		(layers "F.Cu" "B.Cu")
		(net "GND")
	)
	(via
		(at 455.011282 -258.516628)
		(size 0.4572)
		(drill 0.2032)
		(layers "F.Cu" "B.Cu")
		(net "GND")
	)
	(via
		(at 411.958282 -271.266666)
		(size 0.4572)
		(drill 0.2032)
		(layers "F.Cu" "B.Cu")
		(net "GND")
	)
	(via
		(at 392.667998 -401.492212)
		(size 0.4572)
		(drill 0.254)
		(layers "F.Cu" "B.Cu")
		(net "GND")
	)
	(via
		(at 54.508146 -289.11677)
		(size 0.4572)
		(drill 0.2032)
		(layers "F.Cu" "B.Cu")
		(net "GND")
	)
	(via
		(at 360.050334 -223.575626)
		(size 0.4572)
		(drill 0.2032)
		(layers "F.Cu" "B.Cu")
		(net "GND")
	)
	(via
		(at 129.136648 -275.8948)
		(size 0.4572)
		(drill 0.2032)
		(layers "F.Cu" "B.Cu")
		(net "GND")
	)
	(via
		(at 432.379882 -262.76681)
		(size 0.4572)
		(drill 0.2032)
		(layers "F.Cu" "B.Cu")
		(net "GND")
	)
	(via
		(at 51.467004 -12.37488)
		(size 0.508)
		(drill 0.254)
		(layers "F.Cu" "B.Cu")
		(net "GND")
	)
	(via
		(at 420.736014 -199.01662)
		(size 0.4572)
		(drill 0.2032)
		(layers "F.Cu" "B.Cu")
		(net "GND")
	)
	(via
		(at 52.082446 -273.816572)
		(size 0.4572)
		(drill 0.2032)
		(layers "F.Cu" "B.Cu")
		(net "GND")
	)
	(via
		(at 252.09627 -45.860462)
		(size 0.508)
		(drill 0.254)
		(layers "F.Cu" "B.Cu")
		(net "GND")
	)
	(via
		(at 347.473016 -268.569694)
		(size 0.4572)
		(drill 0.2032)
		(layers "F.Cu" "B.Cu")
		(net "GND")
	)
	(via
		(at 337.299808 -50.450496)
		(size 0.4572)
		(drill 0.2032)
		(layers "F.Cu" "B.Cu")
		(net "GND")
	)
	(via
		(at 408.893772 -19.125438)
		(size 0.508)
		(drill 0.254)
		(layers "F.Cu" "B.Cu")
		(net "GND")
	)
	(via
		(at 32.445452 -167.443404)
		(size 0.508)
		(drill 0.254)
		(layers "F.Cu" "B.Cu")
		(net "GND")
	)
	(via
		(at 212.724746 -236.416596)
		(size 0.4572)
		(drill 0.2032)
		(layers "F.Cu" "B.Cu")
		(net "GND")
	)
	(via
		(at 43.520614 -262.76681)
		(size 0.4572)
		(drill 0.2032)
		(layers "F.Cu" "B.Cu")
		(net "GND")
	)
	(via
		(at 166.0652 -126.67996)
		(size 0.508)
		(drill 0.254)
		(layers "F.Cu" "B.Cu")
		(net "GND")
	)
	(via
		(at 373.787416 -284.847538)
		(size 0.4572)
		(drill 0.2032)
		(layers "F.Cu" "B.Cu")
		(net "GND")
	)
	(via
		(at 135.135366 -222.761556)
		(size 0.4572)
		(drill 0.2032)
		(layers "F.Cu" "B.Cu")
		(net "GND")
	)
	(via
		(at 18.679414 -198.166736)
		(size 0.4572)
		(drill 0.2032)
		(layers "F.Cu" "B.Cu")
		(net "GND")
	)
	(via
		(at 68.76923 -52.720748)
		(size 0.508)
		(drill 0.254)
		(layers "F.Cu" "B.Cu")
		(net "GND")
	)
	(via
		(at 26.223214 -269.566644)
		(size 0.4572)
		(drill 0.2032)
		(layers "F.Cu" "B.Cu")
		(net "GND")
	)
	(via
		(at 43.754548 -352.401886)
		(size 0.49022)
		(drill 0.254)
		(layers "F.Cu" "B.Cu")
		(net "GND")
	)
	(via
		(at 44.754546 -283.166566)
		(size 0.4572)
		(drill 0.2032)
		(layers "F.Cu" "B.Cu")
		(net "GND")
	)
	(via
		(at 27.672284 -323.434456)
		(size 0.4572)
		(drill 0.2032)
		(layers "F.Cu" "B.Cu")
		(net "GND")
	)
	(via
		(at 186.649614 -278.916638)
		(size 0.4572)
		(drill 0.2032)
		(layers "F.Cu" "B.Cu")
		(net "GND")
	)
	(via
		(at 351.351088 -403.883876)
		(size 0.4064)
		(drill 0.2032)
		(layers "F.Cu" "B.Cu")
		(net "GND")
	)
	(via
		(at 417.002976 -291.666676)
		(size 0.4572)
		(drill 0.2032)
		(layers "F.Cu" "B.Cu")
		(net "GND")
	)
	(via
		(at 26.223214 -310.366664)
		(size 0.4572)
		(drill 0.2032)
		(layers "F.Cu" "B.Cu")
		(net "GND")
	)
	(via
		(at 218.52763 -132.629148)
		(size 0.508)
		(drill 0.254)
		(layers "F.Cu" "B.Cu")
		(net "GND")
	)
	(via
		(at 462.555082 -277.216616)
		(size 0.4572)
		(drill 0.2032)
		(layers "F.Cu" "B.Cu")
		(net "GND")
	)
	(via
		(at 101.302566 -226.017328)
		(size 0.4572)
		(drill 0.2032)
		(layers "F.Cu" "B.Cu")
		(net "GND")
	)
	(via
		(at 197.637146 -236.416596)
		(size 0.4572)
		(drill 0.2032)
		(layers "F.Cu" "B.Cu")
		(net "GND")
	)
	(via
		(at 308.35092 -425.831)
		(size 0.508)
		(drill 0.254)
		(layers "F.Cu" "B.Cu")
		(net "GND")
	)
	(via
		(at 405.648414 -212.616796)
		(size 0.4572)
		(drill 0.2032)
		(layers "F.Cu" "B.Cu")
		(net "GND")
	)
	(via
		(at 167.461946 -227.066602)
		(size 0.4572)
		(drill 0.2032)
		(layers "F.Cu" "B.Cu")
		(net "GND")
	)
	(via
		(at 382.135634 -237.411514)
		(size 0.4572)
		(drill 0.2032)
		(layers "F.Cu" "B.Cu")
		(net "GND")
	)
	(via
		(at 292.694614 -212.616796)
		(size 0.4572)
		(drill 0.2032)
		(layers "F.Cu" "B.Cu")
		(net "GND")
	)
	(via
		(at 157.349952 -432.451256)
		(size 0.4572)
		(drill 0.2032)
		(layers "F.Cu" "B.Cu")
		(net "GND")
	)
	(via
		(at 161.808414 -297.616626)
		(size 0.4572)
		(drill 0.2032)
		(layers "F.Cu" "B.Cu")
		(net "GND")
	)
	(via
		(at 339.014562 -278.336502)
		(size 0.4572)
		(drill 0.2032)
		(layers "F.Cu" "B.Cu")
		(net "GND")
	)
	(via
		(at 177.561748 -351.414588)
		(size 0.508)
		(drill 0.254)
		(layers "F.Cu" "B.Cu")
		(net "GND")
	)
	(via
		(at 381.761238 -410.664152)
		(size 0.4572)
		(drill 0.254)
		(layers "F.Cu" "B.Cu")
		(net "GND")
	)
	(via
		(at 420.156894 -7.215124)
		(size 0.508)
		(drill 0.254)
		(layers "F.Cu" "B.Cu")
		(net "GND")
	)
	(via
		(at 439.923682 -219.41663)
		(size 0.4572)
		(drill 0.2032)
		(layers "F.Cu" "B.Cu")
		(net "GND")
	)
	(via
		(at 364.279434 -219.506038)
		(size 0.4572)
		(drill 0.2032)
		(layers "F.Cu" "B.Cu")
		(net "GND")
	)
	(via
		(at 91.074494 -289.807142)
		(size 0.4572)
		(drill 0.2032)
		(layers "F.Cu" "B.Cu")
		(net "GND")
	)
	(via
		(at 69.250052 -433.747164)
		(size 0.4572)
		(drill 0.2032)
		(layers "F.Cu" "B.Cu")
		(net "GND")
	)
	(via
		(at 373.787416 -281.59202)
		(size 0.4572)
		(drill 0.2032)
		(layers "F.Cu" "B.Cu")
		(net "GND")
	)
	(via
		(at 309.992014 -199.01662)
		(size 0.4572)
		(drill 0.2032)
		(layers "F.Cu" "B.Cu")
		(net "GND")
	)
	(via
		(at 46.964346 -225.36658)
		(size 0.4572)
		(drill 0.2032)
		(layers "F.Cu" "B.Cu")
		(net "GND")
	)
	(via
		(at 425.817284 -360.937556)
		(size 0.49022)
		(drill 0.254)
		(layers "F.Cu" "B.Cu")
		(net "GND")
	)
	(via
		(at 292.694614 -309.51678)
		(size 0.4572)
		(drill 0.2032)
		(layers "F.Cu" "B.Cu")
		(net "GND")
	)
	(via
		(at 306.963572 -44.237148)
		(size 0.508)
		(drill 0.254)
		(layers "F.Cu" "B.Cu")
		(net "GND")
	)
	(via
		(at 54.333648 -156.23159)
		(size 0.49022)
		(drill 0.254)
		(layers "F.Cu" "B.Cu")
		(net "GND")
	)
	(via
		(at 126.677166 -219.506038)
		(size 0.4572)
		(drill 0.2032)
		(layers "F.Cu" "B.Cu")
		(net "GND")
	)
	(via
		(at 161.808414 -282.316682)
		(size 0.4572)
		(drill 0.2032)
		(layers "F.Cu" "B.Cu")
		(net "GND")
	)
	(via
		(at 39.420546 -311.216802)
		(size 0.4572)
		(drill 0.2032)
		(layers "F.Cu" "B.Cu")
		(net "GND")
	)
	(via
		(at 175.22825 -400.789902)
		(size 0.508)
		(drill 0.254)
		(layers "F.Cu" "B.Cu")
		(net "GND")
	)
	(via
		(at 285.150814 -242.3668)
		(size 0.4572)
		(drill 0.2032)
		(layers "F.Cu" "B.Cu")
		(net "GND")
	)
	(via
		(at 14.579346 -260.21665)
		(size 0.4572)
		(drill 0.2032)
		(layers "F.Cu" "B.Cu")
		(net "GND")
	)
	(via
		(at 197.637146 -272.116804)
		(size 0.4572)
		(drill 0.2032)
		(layers "F.Cu" "B.Cu")
		(net "GND")
	)
	(via
		(at 397.35125 -403.883876)
		(size 0.4064)
		(drill 0.2032)
		(layers "F.Cu" "B.Cu")
		(net "GND")
	)
	(via
		(at 164.018214 -306.96662)
		(size 0.4572)
		(drill 0.2032)
		(layers "F.Cu" "B.Cu")
		(net "GND")
	)
	(via
		(at 182.549546 -201.56678)
		(size 0.4572)
		(drill 0.2032)
		(layers "F.Cu" "B.Cu")
		(net "GND")
	)
	(via
		(at 286.033718 -368.428016)
		(size 0.508)
		(drill 0.254)
		(layers "F.Cu" "B.Cu")
		(net "GND")
	)
	(via
		(at 29.666946 -281.466798)
		(size 0.4572)
		(drill 0.2032)
		(layers "F.Cu" "B.Cu")
		(net "GND")
	)
	(via
		(at 445.577214 -195.616576)
		(size 0.4572)
		(drill 0.2032)
		(layers "F.Cu" "B.Cu")
		(net "GND")
	)
	(via
		(at 259.075682 -272.966688)
		(size 0.4572)
		(drill 0.2032)
		(layers "F.Cu" "B.Cu")
		(net "GND")
	)
	(via
		(at 274.163282 -306.96662)
		(size 0.4572)
		(drill 0.2032)
		(layers "F.Cu" "B.Cu")
		(net "GND")
	)
	(via
		(at 255.841246 -107.361228)
		(size 0.508)
		(drill 0.254)
		(layers "F.Cu" "B.Cu")
		(net "GND")
	)
	(via
		(at 22.123146 -301.866808)
		(size 0.4572)
		(drill 0.2032)
		(layers "F.Cu" "B.Cu")
		(net "GND")
	)
	(via
		(at 394.349986 -429.147224)
		(size 0.4572)
		(drill 0.2032)
		(layers "F.Cu" "B.Cu")
		(net "GND")
	)
	(via
		(at 413.50438 -167.731948)
		(size 0.508)
		(drill 0.254)
		(layers "F.Cu" "B.Cu")
		(net "GND")
	)
	(via
		(at 361.87126 -55.884572)
		(size 0.508)
		(drill 0.254)
		(layers "F.Cu" "B.Cu")
		(net "GND")
	)
	(via
		(at 33.767014 -245.76659)
		(size 0.4572)
		(drill 0.2032)
		(layers "F.Cu" "B.Cu")
		(net "GND")
	)
	(via
		(at 92.014548 -279.964134)
		(size 0.4572)
		(drill 0.2032)
		(layers "F.Cu" "B.Cu")
		(net "GND")
	)
	(via
		(at 254.975614 -261.916672)
		(size 0.4572)
		(drill 0.2032)
		(layers "F.Cu" "B.Cu")
		(net "GND")
	)
	(via
		(at 387.549898 -338.63407)
		(size 0.6604)
		(drill 0.3302)
		(layers "F.Cu" "B.Cu")
		(net "GND")
	)
	(via
		(at 104.231694 -266.941808)
		(size 0.4572)
		(drill 0.2032)
		(layers "F.Cu" "B.Cu")
		(net "GND")
	)
	(via
		(at 455.011282 -272.966688)
		(size 0.4572)
		(drill 0.2032)
		(layers "F.Cu" "B.Cu")
		(net "GND")
	)
	(via
		(at 328.67727 -342.641428)
		(size 0.49022)
		(drill 0.254)
		(layers "F.Cu" "B.Cu")
		(net "GND")
	)
	(via
		(at 123.027694 -268.569694)
		(size 0.4572)
		(drill 0.2032)
		(layers "F.Cu" "B.Cu")
		(net "GND")
	)
	(via
		(at 411.958282 -224.516696)
		(size 0.4572)
		(drill 0.2032)
		(layers "F.Cu" "B.Cu")
		(net "GND")
	)
	(via
		(at 94.985078 -331.776832)
		(size 0.49022)
		(drill 0.254)
		(layers "F.Cu" "B.Cu")
		(net "GND")
	)
	(via
		(at 375.595896 -415.846006)
		(size 0.508)
		(drill 0.254)
		(layers "F.Cu" "B.Cu")
		(net "GND")
	)
	(via
		(at 317.250064 -426.54728)
		(size 0.4572)
		(drill 0.2032)
		(layers "F.Cu" "B.Cu")
		(net "GND")
	)
	(via
		(at 291.460682 -262.76681)
		(size 0.4572)
		(drill 0.2032)
		(layers "F.Cu" "B.Cu")
		(net "GND")
	)
	(via
		(at 106.324908 -100.259388)
		(size 0.508)
		(drill 0.254)
		(layers "F.Cu" "B.Cu")
		(net "GND")
	)
	(via
		(at 118.49608 -120.856248)
		(size 0.508)
		(drill 0.254)
		(layers "F.Cu" "B.Cu")
		(net "GND")
	)
	(via
		(at 87.960962 -337.692238)
		(size 0.49022)
		(drill 0.254)
		(layers "F.Cu" "B.Cu")
		(net "GND")
	)
	(via
		(at 451.14464 -150.569168)
		(size 0.508)
		(drill 0.254)
		(layers "F.Cu" "B.Cu")
		(net "GND")
	)
	(via
		(at 186.649614 -295.916604)
		(size 0.4572)
		(drill 0.2032)
		(layers "F.Cu" "B.Cu")
		(net "GND")
	)
	(via
		(at 390.844278 -346.80017)
		(size 0.508)
		(drill 0.254)
		(layers "F.Cu" "B.Cu")
		(net "GND")
	)
	(via
		(at 33.767014 -230.466646)
		(size 0.4572)
		(drill 0.2032)
		(layers "F.Cu" "B.Cu")
		(net "GND")
	)
	(via
		(at 357.717344 -331.703426)
		(size 0.508)
		(drill 0.254)
		(layers "F.Cu" "B.Cu")
		(net "GND")
	)
	(via
		(at 345.95308 -231.714548)
		(size 0.4572)
		(drill 0.2032)
		(layers "F.Cu" "B.Cu")
		(net "GND")
	)
	(via
		(at 418.881306 -153.562304)
		(size 0.49022)
		(drill 0.254)
		(layers "F.Cu" "B.Cu")
		(net "GND")
	)
	(via
		(at 429.519334 -183.428132)
		(size 0.508)
		(drill 0.254)
		(layers "F.Cu" "B.Cu")
		(net "GND")
	)
	(via
		(at 416.575494 -179.704238)
		(size 0.49022)
		(drill 0.254)
		(layers "F.Cu" "B.Cu")
		(net "GND")
	)
	(via
		(at 7.035546 -311.216802)
		(size 0.4572)
		(drill 0.2032)
		(layers "F.Cu" "B.Cu")
		(net "GND")
	)
	(via
		(at 458.455014 -246.616728)
		(size 0.4572)
		(drill 0.2032)
		(layers "F.Cu" "B.Cu")
		(net "GND")
	)
	(via
		(at 53.267102 -12.37488)
		(size 0.508)
		(drill 0.254)
		(layers "F.Cu" "B.Cu")
		(net "GND")
	)
	(via
		(at 43.520614 -308.666642)
		(size 0.4572)
		(drill 0.2032)
		(layers "F.Cu" "B.Cu")
		(net "GND")
	)
	(via
		(at 464.764882 -314.616592)
		(size 0.4572)
		(drill 0.2032)
		(layers "F.Cu" "B.Cu")
		(net "GND")
	)
	(via
		(at 400.140678 -409.396184)
		(size 0.4572)
		(drill 0.254)
		(layers "F.Cu" "B.Cu")
		(net "GND")
	)
	(via
		(at 60.367418 -261.10565)
		(size 0.6604)
		(drill 0.3302)
		(layers "F.Cu" "B.Cu")
		(net "GND")
	)
	(via
		(at 339.484462 -271.011396)
		(size 0.4572)
		(drill 0.2032)
		(layers "F.Cu" "B.Cu")
		(net "GND")
	)
	(via
		(at 368.038634 -216.25052)
		(size 0.4572)
		(drill 0.2032)
		(layers "F.Cu" "B.Cu")
		(net "GND")
	)
	(via
		(at 172.795946 -276.366732)
		(size 0.4572)
		(drill 0.2032)
		(layers "F.Cu" "B.Cu")
		(net "GND")
	)
	(via
		(at 175.005746 -307.816758)
		(size 0.4572)
		(drill 0.2032)
		(layers "F.Cu" "B.Cu")
		(net "GND")
	)
	(via
		(at 330.492354 -57.2643)
		(size 0.4572)
		(drill 0.2032)
		(layers "F.Cu" "B.Cu")
		(net "GND")
	)
	(via
		(at 91.704922 -332.512924)
		(size 0.508)
		(drill 0.254)
		(layers "F.Cu" "B.Cu")
		(net "GND")
	)
	(via
		(at 54.333648 -163.60775)
		(size 0.49022)
		(drill 0.254)
		(layers "F.Cu" "B.Cu")
		(net "GND")
	)
	(via
		(at 332.697328 -42.811446)
		(size 0.4572)
		(drill 0.2032)
		(layers "F.Cu" "B.Cu")
		(net "GND")
	)
	(via
		(at 445.621156 -69.933566)
		(size 0.508)
		(drill 0.254)
		(layers "F.Cu" "B.Cu")
		(net "GND")
	)
	(via
		(at 191.983614 -241.516662)
		(size 0.4572)
		(drill 0.2032)
		(layers "F.Cu" "B.Cu")
		(net "GND")
	)
	(via
		(at 52.298346 -221.96679)
		(size 0.4572)
		(drill 0.2032)
		(layers "F.Cu" "B.Cu")
		(net "GND")
	)
	(via
		(at 430.489614 -229.616762)
		(size 0.4572)
		(drill 0.2032)
		(layers "F.Cu" "B.Cu")
		(net "GND")
	)
	(via
		(at 360.05008 -238.225584)
		(size 0.4572)
		(drill 0.2032)
		(layers "F.Cu" "B.Cu")
		(net "GND")
	)
	(via
		(at 406.267158 -410.664152)
		(size 0.4572)
		(drill 0.254)
		(layers "F.Cu" "B.Cu")
		(net "GND")
	)
	(via
		(at 287.360614 -229.616762)
		(size 0.4572)
		(drill 0.2032)
		(layers "F.Cu" "B.Cu")
		(net "GND")
	)
	(via
		(at 370.229638 -187.71489)
		(size 0.508)
		(drill 0.254)
		(layers "F.Cu" "B.Cu")
		(net "GND")
	)
	(via
		(at 140.941806 -406.34666)
		(size 0.4572)
		(drill 0.254)
		(layers "F.Cu" "B.Cu")
		(net "GND")
	)
	(via
		(at 257.185414 -214.316564)
		(size 0.4572)
		(drill 0.2032)
		(layers "F.Cu" "B.Cu")
		(net "GND")
	)
	(via
		(at 14.579346 -217.716608)
		(size 0.4572)
		(drill 0.2032)
		(layers "F.Cu" "B.Cu")
		(net "GND")
	)
	(via
		(at 26.223214 -308.666642)
		(size 0.4572)
		(drill 0.2032)
		(layers "F.Cu" "B.Cu")
		(net "GND")
	)
	(via
		(at 169.352214 -224.516696)
		(size 0.4572)
		(drill 0.2032)
		(layers "F.Cu" "B.Cu")
		(net "GND")
	)
	(via
		(at 116.437156 -414.0073)
		(size 0.508)
		(drill 0.254)
		(layers "F.Cu" "B.Cu")
		(net "GND")
	)
	(via
		(at 306.548282 -196.466714)
		(size 0.4572)
		(drill 0.2032)
		(layers "F.Cu" "B.Cu")
		(net "GND")
	)
	(via
		(at 110.340394 -261.245096)
		(size 0.4572)
		(drill 0.2032)
		(layers "F.Cu" "B.Cu")
		(net "GND")
	)
	(via
		(at 398.693386 -6.586474)
		(size 0.508)
		(drill 0.254)
		(layers "F.Cu" "B.Cu")
		(net "GND")
	)
	(via
		(at 304.338482 -233.86669)
		(size 0.4572)
		(drill 0.2032)
		(layers "F.Cu" "B.Cu")
		(net "GND")
	)
	(via
		(at 443.367414 -311.216802)
		(size 0.4572)
		(drill 0.2032)
		(layers "F.Cu" "B.Cu")
		(net "GND")
	)
	(via
		(at 166.890954 -410.030168)
		(size 0.4064)
		(drill 0.2032)
		(layers "F.Cu" "B.Cu")
		(net "GND")
	)
	(via
		(at 364.389416 -284.847538)
		(size 0.4572)
		(drill 0.2032)
		(layers "F.Cu" "B.Cu")
		(net "GND")
	)
	(via
		(at 26.223214 -211.766658)
		(size 0.4572)
		(drill 0.2032)
		(layers "F.Cu" "B.Cu")
		(net "GND")
	)
	(via
		(at 417.292282 -230.466646)
		(size 0.4572)
		(drill 0.2032)
		(layers "F.Cu" "B.Cu")
		(net "GND")
	)
	(via
		(at 289.250882 -249.166634)
		(size 0.4572)
		(drill 0.2032)
		(layers "F.Cu" "B.Cu")
		(net "GND")
	)
	(via
		(at 99.532948 -268.569694)
		(size 0.4572)
		(drill 0.2032)
		(layers "F.Cu" "B.Cu")
		(net "GND")
	)
	(via
		(at 115.979194 -272.639282)
		(size 0.4572)
		(drill 0.2032)
		(layers "F.Cu" "B.Cu")
		(net "GND")
	)
	(via
		(at 417.292282 -261.066788)
		(size 0.4572)
		(drill 0.2032)
		(layers "F.Cu" "B.Cu")
		(net "GND")
	)
	(via
		(at 77.95641 -406.370536)
		(size 0.4572)
		(drill 0.254)
		(layers "F.Cu" "B.Cu")
		(net "GND")
	)
	(via
		(at 326.571356 -406.370536)
		(size 0.4572)
		(drill 0.254)
		(layers "F.Cu" "B.Cu")
		(net "GND")
	)
	(via
		(at 391.22477 -400.858228)
		(size 0.4064)
		(drill 0.2032)
		(layers "F.Cu" "B.Cu")
		(net "GND")
	)
	(via
		(at 43.520614 -312.91657)
		(size 0.4572)
		(drill 0.2032)
		(layers "F.Cu" "B.Cu")
		(net "GND")
	)
	(via
		(at 20.889214 -238.116618)
		(size 0.4572)
		(drill 0.2032)
		(layers "F.Cu" "B.Cu")
		(net "GND")
	)
	(via
		(at 191.983614 -211.766658)
		(size 0.4572)
		(drill 0.2032)
		(layers "F.Cu" "B.Cu")
		(net "GND")
	)
	(via
		(at 135.605266 -238.225584)
		(size 0.4572)
		(drill 0.2032)
		(layers "F.Cu" "B.Cu")
		(net "GND")
	)
	(via
		(at 14.579346 -290.816792)
		(size 0.4572)
		(drill 0.2032)
		(layers "F.Cu" "B.Cu")
		(net "GND")
	)
	(via
		(at 213.879684 -323.358256)
		(size 0.4572)
		(drill 0.2032)
		(layers "F.Cu" "B.Cu")
		(net "GND")
	)
	(via
		(at 24.332946 -298.466764)
		(size 0.4572)
		(drill 0.2032)
		(layers "F.Cu" "B.Cu")
		(net "GND")
	)
	(via
		(at 43.520614 -232.166668)
		(size 0.4572)
		(drill 0.2032)
		(layers "F.Cu" "B.Cu")
		(net "GND")
	)
	(via
		(at 179.105814 -224.516696)
		(size 0.4572)
		(drill 0.2032)
		(layers "F.Cu" "B.Cu")
		(net "GND")
	)
	(via
		(at 87.675466 -241.481102)
		(size 0.4572)
		(drill 0.2032)
		(layers "F.Cu" "B.Cu")
		(net "GND")
	)
	(via
		(at 174.942754 -350.093788)
		(size 0.508)
		(drill 0.254)
		(layers "F.Cu" "B.Cu")
		(net "GND")
	)
	(via
		(at 320.083688 -407.00452)
		(size 0.4064)
		(drill 0.2032)
		(layers "F.Cu" "B.Cu")
		(net "GND")
	)
	(via
		(at 59.842146 -279.766776)
		(size 0.4572)
		(drill 0.2032)
		(layers "F.Cu" "B.Cu")
		(net "GND")
	)
	(via
		(at 389.24357 -403.883876)
		(size 0.4064)
		(drill 0.2032)
		(layers "F.Cu" "B.Cu")
		(net "GND")
	)
	(via
		(at 305.4604 -192.954148)
		(size 0.508)
		(drill 0.254)
		(layers "F.Cu" "B.Cu")
		(net "GND")
	)
	(via
		(at 120.97639 -244.430804)
		(size 0.4572)
		(drill 0.2032)
		(layers "F.Cu" "B.Cu")
		(net "GND")
	)
	(via
		(at 380.365762 -279.964134)
		(size 0.4572)
		(drill 0.2032)
		(layers "F.Cu" "B.Cu")
		(net "GND")
	)
	(via
		(at 283.916882 -250.866656)
		(size 0.4572)
		(drill 0.2032)
		(layers "F.Cu" "B.Cu")
		(net "GND")
	)
	(via
		(at 368.916204 -244.43055)
		(size 0.4572)
		(drill 0.2032)
		(layers "F.Cu" "B.Cu")
		(net "GND")
	)
	(via
		(at 422.945814 -278.066754)
		(size 0.4572)
		(drill 0.2032)
		(layers "F.Cu" "B.Cu")
		(net "GND")
	)
	(via
		(at 464.764882 -267.866622)
		(size 0.4572)
		(drill 0.2032)
		(layers "F.Cu" "B.Cu")
		(net "GND")
	)
	(via
		(at 464.764882 -196.466714)
		(size 0.4572)
		(drill 0.2032)
		(layers "F.Cu" "B.Cu")
		(net "GND")
	)
	(via
		(at 254.27051 -78.008988)
		(size 0.508)
		(drill 0.254)
		(layers "F.Cu" "B.Cu")
		(net "GND")
	)
	(via
		(at 104.16286 -61.450728)
		(size 0.508)
		(drill 0.254)
		(layers "F.Cu" "B.Cu")
		(net "GND")
	)
	(via
		(at 24.332946 -263.616694)
		(size 0.4572)
		(drill 0.2032)
		(layers "F.Cu" "B.Cu")
		(net "GND")
	)
	(via
		(at 279.816814 -217.716608)
		(size 0.4572)
		(drill 0.2032)
		(layers "F.Cu" "B.Cu")
		(net "GND")
	)
	(via
		(at 336.665316 -284.033722)
		(size 0.4572)
		(drill 0.2032)
		(layers "F.Cu" "B.Cu")
		(net "GND")
	)
	(via
		(at 459.940152 -323.429376)
		(size 0.4572)
		(drill 0.2032)
		(layers "F.Cu" "B.Cu")
		(net "GND")
	)
	(via
		(at 135.610854 -249.073924)
		(size 0.4572)
		(drill 0.2032)
		(layers "F.Cu" "B.Cu")
		(net "GND")
	)
	(via
		(at 108.65866 -127.218948)
		(size 0.508)
		(drill 0.254)
		(layers "F.Cu" "B.Cu")
		(net "GND")
	)
	(via
		(at 460.664814 -195.616576)
		(size 0.4572)
		(drill 0.2032)
		(layers "F.Cu" "B.Cu")
		(net "GND")
	)
	(via
		(at 46.690788 -437.011318)
		(size 0.508)
		(drill 0.254)
		(layers "F.Cu" "B.Cu")
		(net "GND")
	)
	(via
		(at 14.579346 -201.56678)
		(size 0.4572)
		(drill 0.2032)
		(layers "F.Cu" "B.Cu")
		(net "GND")
	)
	(via
		(at 47.782226 -401.492212)
		(size 0.4572)
		(drill 0.254)
		(layers "F.Cu" "B.Cu")
		(net "GND")
	)
	(via
		(at 144.366234 -407.00452)
		(size 0.4064)
		(drill 0.2032)
		(layers "F.Cu" "B.Cu")
		(net "GND")
	)
	(via
		(at 370.027962 -278.336502)
		(size 0.4572)
		(drill 0.2032)
		(layers "F.Cu" "B.Cu")
		(net "GND")
	)
	(via
		(at 62.051946 -279.766776)
		(size 0.4572)
		(drill 0.2032)
		(layers "F.Cu" "B.Cu")
		(net "GND")
	)
	(via
		(at 53.267102 -10.16508)
		(size 0.508)
		(drill 0.254)
		(layers "F.Cu" "B.Cu")
		(net "GND")
	)
	(via
		(at 296.794682 -271.266666)
		(size 0.4572)
		(drill 0.2032)
		(layers "F.Cu" "B.Cu")
		(net "GND")
	)
	(via
		(at 18.679414 -207.51673)
		(size 0.4572)
		(drill 0.2032)
		(layers "F.Cu" "B.Cu")
		(net "GND")
	)
	(via
		(at 43.520614 -278.916638)
		(size 0.4572)
		(drill 0.2032)
		(layers "F.Cu" "B.Cu")
		(net "GND")
	)
	(via
		(at 136.349994 -439.651394)
		(size 0.4572)
		(drill 0.2032)
		(layers "F.Cu" "B.Cu")
		(net "GND")
	)
	(via
		(at 89.664794 -264.50036)
		(size 0.4572)
		(drill 0.2032)
		(layers "F.Cu" "B.Cu")
		(net "GND")
	)
	(via
		(at 307.594254 -238.966756)
		(size 0.4572)
		(drill 0.2032)
		(layers "F.Cu" "B.Cu")
		(net "GND")
	)
	(via
		(at 460.664814 -263.616694)
		(size 0.4572)
		(drill 0.2032)
		(layers "F.Cu" "B.Cu")
		(net "GND")
	)
	(via
		(at 305.128676 -410.664152)
		(size 0.4572)
		(drill 0.254)
		(layers "F.Cu" "B.Cu")
		(net "GND")
	)
	(via
		(at 114.929412 -215.436704)
		(size 0.4572)
		(drill 0.2032)
		(layers "F.Cu" "B.Cu")
		(net "GND")
	)
	(via
		(at 187.883546 -300.166786)
		(size 0.4572)
		(drill 0.2032)
		(layers "F.Cu" "B.Cu")
		(net "GND")
	)
	(via
		(at 26.496772 -416.83305)
		(size 0.508)
		(drill 0.254)
		(layers "F.Cu" "B.Cu")
		(net "GND")
	)
	(via
		(at 56.251856 -161.572702)
		(size 0.508)
		(drill 0.254)
		(layers "F.Cu" "B.Cu")
		(net "GND")
	)
	(via
		(at 354.881434 -216.25052)
		(size 0.4572)
		(drill 0.2032)
		(layers "F.Cu" "B.Cu")
		(net "GND")
	)
	(via
		(at 378.84608 -231.714548)
		(size 0.4572)
		(drill 0.2032)
		(layers "F.Cu" "B.Cu")
		(net "GND")
	)
	(via
		(at 335.399126 -39.443152)
		(size 0.4572)
		(drill 0.2032)
		(layers "F.Cu" "B.Cu")
		(net "GND")
	)
	(via
		(at 285.150814 -267.016738)
		(size 0.4572)
		(drill 0.2032)
		(layers "F.Cu" "B.Cu")
		(net "GND")
	)
	(via
		(at 37.210746 -261.916672)
		(size 0.4572)
		(drill 0.2032)
		(layers "F.Cu" "B.Cu")
		(net "GND")
	)
	(via
		(at 51.064414 -224.516696)
		(size 0.4572)
		(drill 0.2032)
		(layers "F.Cu" "B.Cu")
		(net "GND")
	)
	(via
		(at 438.637172 -25.899618)
		(size 0.508)
		(drill 0.254)
		(layers "F.Cu" "B.Cu")
		(net "GND")
	)
	(via
		(at 262.519414 -279.766776)
		(size 0.4572)
		(drill 0.2032)
		(layers "F.Cu" "B.Cu")
		(net "GND")
	)
	(via
		(at 209.281014 -215.166702)
		(size 0.4572)
		(drill 0.2032)
		(layers "F.Cu" "B.Cu")
		(net "GND")
	)
	(via
		(at 58.065162 -151.59228)
		(size 0.508)
		(drill 0.254)
		(layers "F.Cu" "B.Cu")
		(net "GND")
	)
	(via
		(at 358.9909 -55.884572)
		(size 0.508)
		(drill 0.254)
		(layers "F.Cu" "B.Cu")
		(net "GND")
	)
	(via
		(at 142.0622 -107.373928)
		(size 0.508)
		(drill 0.254)
		(layers "F.Cu" "B.Cu")
		(net "GND")
	)
	(via
		(at 292.694614 -214.316564)
		(size 0.4572)
		(drill 0.2032)
		(layers "F.Cu" "B.Cu")
		(net "GND")
	)
	(via
		(at 132.895594 -280.778204)
		(size 0.4572)
		(drill 0.2032)
		(layers "F.Cu" "B.Cu")
		(net "GND")
	)
	(via
		(at 86.845394 -254.733552)
		(size 0.4318)
		(drill 0.2032)
		(layers "F.Cu" "B.Cu")
		(net "GND")
	)
	(via
		(at 122.562366 -406.370536)
		(size 0.4572)
		(drill 0.254)
		(layers "F.Cu" "B.Cu")
		(net "GND")
	)
	(via
		(at 276.373082 -288.266632)
		(size 0.4572)
		(drill 0.2032)
		(layers "F.Cu" "B.Cu")
		(net "GND")
	)
	(via
		(at 164.298376 -205.816708)
		(size 0.4572)
		(drill 0.2032)
		(layers "F.Cu" "B.Cu")
		(net "GND")
	)
	(via
		(at 334.414876 -404.51786)
		(size 0.4572)
		(drill 0.254)
		(layers "F.Cu" "B.Cu")
		(net "GND")
	)
	(via
		(at 58.0517 -106.784648)
		(size 0.508)
		(drill 0.254)
		(layers "F.Cu" "B.Cu")
		(net "GND")
	)
	(via
		(at 109.77753 -332.363826)
		(size 0.508)
		(drill 0.254)
		(layers "F.Cu" "B.Cu")
		(net "GND")
	)
	(via
		(at 210.514946 -307.816758)
		(size 0.4572)
		(drill 0.2032)
		(layers "F.Cu" "B.Cu")
		(net "GND")
	)
	(via
		(at 52.298346 -227.066602)
		(size 0.4572)
		(drill 0.2032)
		(layers "F.Cu" "B.Cu")
		(net "GND")
	)
	(via
		(at 377.436634 -240.667286)
		(size 0.4572)
		(drill 0.2032)
		(layers "F.Cu" "B.Cu")
		(net "GND")
	)
	(via
		(at 14.579346 -296.766742)
		(size 0.4572)
		(drill 0.2032)
		(layers "F.Cu" "B.Cu")
		(net "GND")
	)
	(via
		(at 38.94709 -18.246344)
		(size 0.508)
		(drill 0.254)
		(layers "F.Cu" "B.Cu")
		(net "GND")
	)
	(via
		(at 272.273014 -199.01662)
		(size 0.4572)
		(drill 0.2032)
		(layers "F.Cu" "B.Cu")
		(net "GND")
	)
	(via
		(at 414.110678 -401.492212)
		(size 0.4572)
		(drill 0.254)
		(layers "F.Cu" "B.Cu")
		(net "GND")
	)
	(via
		(at 374.038368 -333.79283)
		(size 0.508)
		(drill 0.254)
		(layers "F.Cu" "B.Cu")
		(net "GND")
	)
	(via
		(at 127.616966 -247.178322)
		(size 0.4572)
		(drill 0.2032)
		(layers "F.Cu" "B.Cu")
		(net "GND")
	)
	(via
		(at 133.255766 -219.506038)
		(size 0.4572)
		(drill 0.2032)
		(layers "F.Cu" "B.Cu")
		(net "GND")
	)
	(via
		(at 343.713562 -283.219906)
		(size 0.4572)
		(drill 0.2032)
		(layers "F.Cu" "B.Cu")
		(net "GND")
	)
	(via
		(at 261.285482 -207.51673)
		(size 0.4572)
		(drill 0.2032)
		(layers "F.Cu" "B.Cu")
		(net "GND")
	)
	(via
		(at 266.619482 -224.516696)
		(size 0.4572)
		(drill 0.2032)
		(layers "F.Cu" "B.Cu")
		(net "GND")
	)
	(via
		(at 153.194766 -410.664152)
		(size 0.4572)
		(drill 0.254)
		(layers "F.Cu" "B.Cu")
		(net "GND")
	)
	(via
		(at 135.135366 -232.528364)
		(size 0.4572)
		(drill 0.2032)
		(layers "F.Cu" "B.Cu")
		(net "GND")
	)
	(via
		(at 343.373964 -441.225432)
		(size 0.508)
		(drill 0.254)
		(layers "F.Cu" "B.Cu")
		(net "GND")
	)
	(via
		(at 373.317262 -282.405836)
		(size 0.4572)
		(drill 0.2032)
		(layers "F.Cu" "B.Cu")
		(net "GND")
	)
	(via
		(at 460.664814 -248.31675)
		(size 0.4572)
		(drill 0.2032)
		(layers "F.Cu" "B.Cu")
		(net "GND")
	)
	(via
		(at 283.156152 -323.429376)
		(size 0.4572)
		(drill 0.2032)
		(layers "F.Cu" "B.Cu")
		(net "GND")
	)
	(via
		(at 283.916882 -232.166668)
		(size 0.4572)
		(drill 0.2032)
		(layers "F.Cu" "B.Cu")
		(net "GND")
	)
	(via
		(at 388.16153 -400.858228)
		(size 0.4064)
		(drill 0.2032)
		(layers "F.Cu" "B.Cu")
		(net "GND")
	)
	(via
		(at 393.926822 -404.51786)
		(size 0.4572)
		(drill 0.254)
		(layers "F.Cu" "B.Cu")
		(net "GND")
	)
	(via
		(at 430.489614 -273.816572)
		(size 0.4572)
		(drill 0.2032)
		(layers "F.Cu" "B.Cu")
		(net "GND")
	)
	(via
		(at 169.8752 -11.496548)
		(size 0.508)
		(drill 0.254)
		(layers "F.Cu" "B.Cu")
		(net "GND")
	)
	(via
		(at 344.183462 -275.8948)
		(size 0.4572)
		(drill 0.2032)
		(layers "F.Cu" "B.Cu")
		(net "GND")
	)
	(via
		(at 212.798914 -21.637244)
		(size 0.508)
		(drill 0.254)
		(layers "F.Cu" "B.Cu")
		(net "GND")
	)
	(via
		(at 382.35001 -429.147224)
		(size 0.4572)
		(drill 0.2032)
		(layers "F.Cu" "B.Cu")
		(net "GND")
	)
	(via
		(at 95.663766 -247.178322)
		(size 0.4572)
		(drill 0.2032)
		(layers "F.Cu" "B.Cu")
		(net "GND")
	)
	(via
		(at 129.136394 -264.50036)
		(size 0.4572)
		(drill 0.2032)
		(layers "F.Cu" "B.Cu")
		(net "GND")
	)
	(via
		(at 455.011282 -294.216582)
		(size 0.4572)
		(drill 0.2032)
		(layers "F.Cu" "B.Cu")
		(net "GND")
	)
	(via
		(at 209.281014 -262.76681)
		(size 0.4572)
		(drill 0.2032)
		(layers "F.Cu" "B.Cu")
		(net "GND")
	)
	(via
		(at 197.89648 -77.765148)
		(size 0.508)
		(drill 0.254)
		(layers "F.Cu" "B.Cu")
		(net "GND")
	)
	(via
		(at 333.26578 -237.411768)
		(size 0.4572)
		(drill 0.2032)
		(layers "F.Cu" "B.Cu")
		(net "GND")
	)
	(via
		(at 106.471212 -233.34218)
		(size 0.4572)
		(drill 0.2032)
		(layers "F.Cu" "B.Cu")
		(net "GND")
	)
	(via
		(at 126.317248 -254.733552)
		(size 0.4572)
		(drill 0.2032)
		(layers "F.Cu" "B.Cu")
		(net "GND")
	)
	(via
		(at 62.051946 -307.816758)
		(size 0.4572)
		(drill 0.2032)
		(layers "F.Cu" "B.Cu")
		(net "GND")
	)
	(via
		(at 415.402014 -227.066602)
		(size 0.4572)
		(drill 0.2032)
		(layers "F.Cu" "B.Cu")
		(net "GND")
	)
	(via
		(at 105.171748 -281.59202)
		(size 0.4572)
		(drill 0.2032)
		(layers "F.Cu" "B.Cu")
		(net "GND")
	)
	(via
		(at 110.23092 -234.970066)
		(size 0.4572)
		(drill 0.2032)
		(layers "F.Cu" "B.Cu")
		(net "GND")
	)
	(via
		(at 259.564632 -15.339568)
		(size 0.508)
		(drill 0.254)
		(layers "F.Cu" "B.Cu")
		(net "GND")
	)
	(via
		(at 20.889214 -271.266666)
		(size 0.4572)
		(drill 0.2032)
		(layers "F.Cu" "B.Cu")
		(net "GND")
	)
	(via
		(at 350.182434 -226.017328)
		(size 0.4572)
		(drill 0.2032)
		(layers "F.Cu" "B.Cu")
		(net "GND")
	)
	(via
		(at 28.978098 -72.51573)
		(size 0.508)
		(drill 0.254)
		(layers "F.Cu" "B.Cu")
		(net "GND")
	)
	(via
		(at 54.508146 -225.36658)
		(size 0.4572)
		(drill 0.2032)
		(layers "F.Cu" "B.Cu")
		(net "GND")
	)
	(via
		(at 125.737366 -234.15625)
		(size 0.4572)
		(drill 0.2032)
		(layers "F.Cu" "B.Cu")
		(net "GND")
	)
	(via
		(at 385.424934 -220.319854)
		(size 0.4572)
		(drill 0.2032)
		(layers "F.Cu" "B.Cu")
		(net "GND")
	)
	(via
		(at 334.25003 -430.147222)
		(size 0.4572)
		(drill 0.2032)
		(layers "F.Cu" "B.Cu")
		(net "GND")
	)
	(via
		(at 136.075166 -221.133924)
		(size 0.4572)
		(drill 0.2032)
		(layers "F.Cu" "B.Cu")
		(net "GND")
	)
	(via
		(at 337.889342 -32.606742)
		(size 0.508)
		(drill 0.254)
		(layers "F.Cu" "B.Cu")
		(net "GND")
	)
	(via
		(at 11.135614 -222.816674)
		(size 0.4572)
		(drill 0.2032)
		(layers "F.Cu" "B.Cu")
		(net "GND")
	)
	(via
		(at 49.128426 -410.664152)
		(size 0.4572)
		(drill 0.254)
		(layers "F.Cu" "B.Cu")
		(net "GND")
	)
	(via
		(at 428.279814 -238.966756)
		(size 0.4572)
		(drill 0.2032)
		(layers "F.Cu" "B.Cu")
		(net "GND")
	)
	(via
		(at 51.064414 -211.766658)
		(size 0.4572)
		(drill 0.2032)
		(layers "F.Cu" "B.Cu")
		(net "GND")
	)
	(via
		(at 425.74337 -4.95173)
		(size 0.508)
		(drill 0.254)
		(layers "F.Cu" "B.Cu")
		(net "GND")
	)
	(via
		(at 134.815326 -407.638504)
		(size 0.4572)
		(drill 0.254)
		(layers "F.Cu" "B.Cu")
		(net "GND")
	)
	(via
		(at 191.983614 -294.216582)
		(size 0.4572)
		(drill 0.2032)
		(layers "F.Cu" "B.Cu")
		(net "GND")
	)
	(via
		(at 281.707082 -305.266598)
		(size 0.4572)
		(drill 0.2032)
		(layers "F.Cu" "B.Cu")
		(net "GND")
	)
	(via
		(at 449.114672 -20.446238)
		(size 0.508)
		(drill 0.254)
		(layers "F.Cu" "B.Cu")
		(net "GND")
	)
	(via
		(at 396.390114 -4.317746)
		(size 0.508)
		(drill 0.254)
		(layers "F.Cu" "B.Cu")
		(net "GND")
	)
	(via
		(at 33.767014 -216.866724)
		(size 0.4572)
		(drill 0.2032)
		(layers "F.Cu" "B.Cu")
		(net "GND")
	)
	(via
		(at 343.431368 -334.282034)
		(size 0.49022)
		(drill 0.254)
		(layers "F.Cu" "B.Cu")
		(net "GND")
	)
	(via
		(at 98.483166 -226.017328)
		(size 0.4572)
		(drill 0.2032)
		(layers "F.Cu" "B.Cu")
		(net "GND")
	)
	(via
		(at 385.708652 -341.766906)
		(size 0.49022)
		(drill 0.254)
		(layers "F.Cu" "B.Cu")
		(net "GND")
	)
	(via
		(at 417.292282 -198.166736)
		(size 0.4572)
		(drill 0.2032)
		(layers "F.Cu" "B.Cu")
		(net "GND")
	)
	(via
		(at 344.589608 -410.030168)
		(size 0.4064)
		(drill 0.2032)
		(layers "F.Cu" "B.Cu")
		(net "GND")
	)
	(via
		(at 287.360614 -317.166752)
		(size 0.4572)
		(drill 0.2032)
		(layers "F.Cu" "B.Cu")
		(net "GND")
	)
	(via
		(at 55.260494 -155.836874)
		(size 0.49022)
		(drill 0.254)
		(layers "F.Cu" "B.Cu")
		(net "GND")
	)
	(via
		(at 302.664114 -273.816572)
		(size 0.4572)
		(drill 0.2032)
		(layers "F.Cu" "B.Cu")
		(net "GND")
	)
	(via
		(at 341.402162 -39.443152)
		(size 0.4572)
		(drill 0.2032)
		(layers "F.Cu" "B.Cu")
		(net "GND")
	)
	(via
		(at 343.550494 -54.088792)
		(size 0.4572)
		(drill 0.2032)
		(layers "F.Cu" "B.Cu")
		(net "GND")
	)
	(via
		(at 303.782476 -403.249892)
		(size 0.4572)
		(drill 0.254)
		(layers "F.Cu" "B.Cu")
		(net "GND")
	)
	(via
		(at 403.47773 -403.883876)
		(size 0.4064)
		(drill 0.2032)
		(layers "F.Cu" "B.Cu")
		(net "GND")
	)
	(via
		(at 298.260008 -354.868226)
		(size 0.508)
		(drill 0.254)
		(layers "F.Cu" "B.Cu")
		(net "GND")
	)
	(via
		(at 98.253296 -427.447964)
		(size 0.508)
		(drill 0.254)
		(layers "F.Cu" "B.Cu")
		(net "GND")
	)
	(via
		(at 56.398414 -297.616626)
		(size 0.4572)
		(drill 0.2032)
		(layers "F.Cu" "B.Cu")
		(net "GND")
	)
	(via
		(at 407.858214 -311.216802)
		(size 0.4572)
		(drill 0.2032)
		(layers "F.Cu" "B.Cu")
		(net "GND")
	)
	(via
		(at 292.694614 -273.816572)
		(size 0.4572)
		(drill 0.2032)
		(layers "F.Cu" "B.Cu")
		(net "GND")
	)
	(via
		(at 220.519498 -18.289524)
		(size 0.508)
		(drill 0.254)
		(layers "F.Cu" "B.Cu")
		(net "GND")
	)
	(via
		(at 464.764882 -294.216582)
		(size 0.4572)
		(drill 0.2032)
		(layers "F.Cu" "B.Cu")
		(net "GND")
	)
	(via
		(at 254.975614 -251.716794)
		(size 0.4572)
		(drill 0.2032)
		(layers "F.Cu" "B.Cu")
		(net "GND")
	)
	(via
		(at 298.493688 -362.414566)
		(size 0.49022)
		(drill 0.254)
		(layers "F.Cu" "B.Cu")
		(net "GND")
	)
	(via
		(at 38.395402 -350.166178)
		(size 0.508)
		(drill 0.254)
		(layers "F.Cu" "B.Cu")
		(net "GND")
	)
	(via
		(at 236.69752 -387.37794)
		(size 0.508)
		(drill 0.254)
		(layers "F.Cu" "B.Cu")
		(net "GND")
	)
	(via
		(at 67.250056 -425.547282)
		(size 0.4572)
		(drill 0.2032)
		(layers "F.Cu" "B.Cu")
		(net "GND")
	)
	(via
		(at 89.664794 -277.522432)
		(size 0.4572)
		(drill 0.2032)
		(layers "F.Cu" "B.Cu")
		(net "GND")
	)
	(via
		(at 90.25001 -426.54728)
		(size 0.4572)
		(drill 0.2032)
		(layers "F.Cu" "B.Cu")
		(net "GND")
	)
	(via
		(at 58.318146 -410.664152)
		(size 0.4572)
		(drill 0.254)
		(layers "F.Cu" "B.Cu")
		(net "GND")
	)
	(via
		(at 422.945814 -265.316716)
		(size 0.4572)
		(drill 0.2032)
		(layers "F.Cu" "B.Cu")
		(net "GND")
	)
	(via
		(at 52.298346 -278.066754)
		(size 0.4572)
		(drill 0.2032)
		(layers "F.Cu" "B.Cu")
		(net "GND")
	)
	(via
		(at 201.737214 -250.866656)
		(size 0.4572)
		(drill 0.2032)
		(layers "F.Cu" "B.Cu")
		(net "GND")
	)
	(via
		(at 442.133482 -213.46668)
		(size 0.4572)
		(drill 0.2032)
		(layers "F.Cu" "B.Cu")
		(net "GND")
	)
	(via
		(at 302.448214 -290.816792)
		(size 0.4572)
		(drill 0.2032)
		(layers "F.Cu" "B.Cu")
		(net "GND")
	)
	(via
		(at 283.916882 -207.51673)
		(size 0.4572)
		(drill 0.2032)
		(layers "F.Cu" "B.Cu")
		(net "GND")
	)
	(via
		(at 112.710976 -114.925348)
		(size 0.508)
		(drill 0.254)
		(layers "F.Cu" "B.Cu")
		(net "GND")
	)
	(via
		(at 342.66378 -243.922804)
		(size 0.4572)
		(drill 0.2032)
		(layers "F.Cu" "B.Cu")
		(net "GND")
	)
	(via
		(at 400.053302 -404.51786)
		(size 0.4572)
		(drill 0.254)
		(layers "F.Cu" "B.Cu")
		(net "GND")
	)
	(via
		(at 287.360614 -240.666778)
		(size 0.4572)
		(drill 0.2032)
		(layers "F.Cu" "B.Cu")
		(net "GND")
	)
	(via
		(at 113.54308 -414.688528)
		(size 0.508)
		(drill 0.254)
		(layers "F.Cu" "B.Cu")
		(net "GND")
	)
	(via
		(at 378.610622 -400.224244)
		(size 0.4572)
		(drill 0.254)
		(layers "F.Cu" "B.Cu")
		(net "GND")
	)
	(via
		(at 276.373082 -294.216582)
		(size 0.4572)
		(drill 0.2032)
		(layers "F.Cu" "B.Cu")
		(net "GND")
	)
	(via
		(at 114.569494 -265.314176)
		(size 0.4572)
		(drill 0.2032)
		(layers "F.Cu" "B.Cu")
		(net "GND")
	)
	(via
		(at 454.093072 -0.76454)
		(size 0.508)
		(drill 0.254)
		(layers "F.Cu" "B.Cu")
		(net "GND")
	)
	(via
		(at 94.364048 -271.011396)
		(size 0.4572)
		(drill 0.2032)
		(layers "F.Cu" "B.Cu")
		(net "GND")
	)
	(via
		(at 268.829282 -272.966688)
		(size 0.4572)
		(drill 0.2032)
		(layers "F.Cu" "B.Cu")
		(net "GND")
	)
	(via
		(at 134.195566 -242.294918)
		(size 0.4572)
		(drill 0.2032)
		(layers "F.Cu" "B.Cu")
		(net "GND")
	)
	(via
		(at 24.332946 -296.766742)
		(size 0.4572)
		(drill 0.2032)
		(layers "F.Cu" "B.Cu")
		(net "GND")
	)
	(via
		(at 115.716304 -360.83875)
		(size 0.508)
		(drill 0.254)
		(layers "F.Cu" "B.Cu")
		(net "GND")
	)
	(via
		(at 376.496834 -232.528364)
		(size 0.4572)
		(drill 0.2032)
		(layers "F.Cu" "B.Cu")
		(net "GND")
	)
	(via
		(at 73.54697 -404.51786)
		(size 0.4572)
		(drill 0.254)
		(layers "F.Cu" "B.Cu")
		(net "GND")
	)
	(via
		(at 46.964346 -227.066602)
		(size 0.4572)
		(drill 0.2032)
		(layers "F.Cu" "B.Cu")
		(net "GND")
	)
	(via
		(at 125.19533 -441.225432)
		(size 0.508)
		(drill 0.254)
		(layers "F.Cu" "B.Cu")
		(net "GND")
	)
	(via
		(at 393.133072 -0.76454)
		(size 0.508)
		(drill 0.254)
		(layers "F.Cu" "B.Cu")
		(net "GND")
	)
	(via
		(at 243.94668 -39.039546)
		(size 0.508)
		(drill 0.254)
		(layers "F.Cu" "B.Cu")
		(net "GND")
	)
	(via
		(at 132.350002 -437.34736)
		(size 0.4572)
		(drill 0.2032)
		(layers "F.Cu" "B.Cu")
		(net "GND")
	)
	(via
		(at 164.188902 -406.34666)
		(size 0.4572)
		(drill 0.254)
		(layers "F.Cu" "B.Cu")
		(net "GND")
	)
	(via
		(at 390.349994 -436.347362)
		(size 0.4572)
		(drill 0.2032)
		(layers "F.Cu" "B.Cu")
		(net "GND")
	)
	(via
		(at 354.541074 -169.234612)
		(size 0.508)
		(drill 0.254)
		(layers "F.Cu" "B.Cu")
		(net "GND")
	)
	(via
		(at 89.664794 -262.872474)
		(size 0.4572)
		(drill 0.2032)
		(layers "F.Cu" "B.Cu")
		(net "GND")
	)
	(via
		(at 33.767014 -308.666642)
		(size 0.4572)
		(drill 0.2032)
		(layers "F.Cu" "B.Cu")
		(net "GND")
	)
	(via
		(at 389.604758 -403.249892)
		(size 0.4572)
		(drill 0.254)
		(layers "F.Cu" "B.Cu")
		(net "GND")
	)
	(via
		(at 9.245346 -248.31675)
		(size 0.4572)
		(drill 0.2032)
		(layers "F.Cu" "B.Cu")
		(net "GND")
	)
	(via
		(at 264.729214 -272.116804)
		(size 0.4572)
		(drill 0.2032)
		(layers "F.Cu" "B.Cu")
		(net "GND")
	)
	(via
		(at 279.816814 -315.46673)
		(size 0.4572)
		(drill 0.2032)
		(layers "F.Cu" "B.Cu")
		(net "GND")
	)
	(via
		(at 343.133934 -220.319854)
		(size 0.4572)
		(drill 0.2032)
		(layers "F.Cu" "B.Cu")
		(net "GND")
	)
	(via
		(at 392.34999 -433.747164)
		(size 0.4572)
		(drill 0.2032)
		(layers "F.Cu" "B.Cu")
		(net "GND")
	)
	(via
		(at 265.081766 -95.269812)
		(size 0.508)
		(drill 0.254)
		(layers "F.Cu" "B.Cu")
		(net "GND")
	)
	(via
		(at 165.252146 -258.516628)
		(size 0.4572)
		(drill 0.2032)
		(layers "F.Cu" "B.Cu")
		(net "GND")
	)
	(via
		(at 157.349952 -439.651394)
		(size 0.4572)
		(drill 0.2032)
		(layers "F.Cu" "B.Cu")
		(net "GND")
	)
	(via
		(at 461.979264 -119.093488)
		(size 0.508)
		(drill 0.254)
		(layers "F.Cu" "B.Cu")
		(net "GND")
	)
	(via
		(at 22.123146 -268.71676)
		(size 0.4572)
		(drill 0.2032)
		(layers "F.Cu" "B.Cu")
		(net "GND")
	)
	(via
		(at 210.514946 -216.016586)
		(size 0.4572)
		(drill 0.2032)
		(layers "F.Cu" "B.Cu")
		(net "GND")
	)
	(via
		(at 390.58977 -407.00452)
		(size 0.4064)
		(drill 0.2032)
		(layers "F.Cu" "B.Cu")
		(net "GND")
	)
	(via
		(at 270.063214 -225.36658)
		(size 0.4572)
		(drill 0.2032)
		(layers "F.Cu" "B.Cu")
		(net "GND")
	)
	(via
		(at 184.439814 -299.316648)
		(size 0.4572)
		(drill 0.2032)
		(layers "F.Cu" "B.Cu")
		(net "GND")
	)
	(via
		(at 403.349968 -429.147224)
		(size 0.4572)
		(drill 0.2032)
		(layers "F.Cu" "B.Cu")
		(net "GND")
	)
	(via
		(at 43.520614 -269.566644)
		(size 0.4572)
		(drill 0.2032)
		(layers "F.Cu" "B.Cu")
		(net "GND")
	)
	(via
		(at 415.468562 -360.937556)
		(size 0.49022)
		(drill 0.254)
		(layers "F.Cu" "B.Cu")
		(net "GND")
	)
	(via
		(at 372.53164 -69.565012)
		(size 0.508)
		(drill 0.254)
		(layers "F.Cu" "B.Cu")
		(net "GND")
	)
	(via
		(at 311.882282 -213.46668)
		(size 0.4572)
		(drill 0.2032)
		(layers "F.Cu" "B.Cu")
		(net "GND")
	)
	(via
		(at 460.664814 -227.066602)
		(size 0.4572)
		(drill 0.2032)
		(layers "F.Cu" "B.Cu")
		(net "GND")
	)
	(via
		(at 214.615014 -204.116686)
		(size 0.4572)
		(drill 0.2032)
		(layers "F.Cu" "B.Cu")
		(net "GND")
	)
	(via
		(at 442.133482 -224.516696)
		(size 0.4572)
		(drill 0.2032)
		(layers "F.Cu" "B.Cu")
		(net "GND")
	)
	(via
		(at 29.666946 -268.71676)
		(size 0.4572)
		(drill 0.2032)
		(layers "F.Cu" "B.Cu")
		(net "GND")
	)
	(via
		(at 319.25006 -435.0512)
		(size 0.4572)
		(drill 0.2032)
		(layers "F.Cu" "B.Cu")
		(net "GND")
	)
	(via
		(at 427.045882 -258.516628)
		(size 0.4572)
		(drill 0.2032)
		(layers "F.Cu" "B.Cu")
		(net "GND")
	)
	(via
		(at 20.889214 -262.76681)
		(size 0.4572)
		(drill 0.2032)
		(layers "F.Cu" "B.Cu")
		(net "GND")
	)
	(via
		(at 455.011282 -210.066636)
		(size 0.4572)
		(drill 0.2032)
		(layers "F.Cu" "B.Cu")
		(net "GND")
	)
	(via
		(at 161.808414 -230.466646)
		(size 0.4572)
		(drill 0.2032)
		(layers "F.Cu" "B.Cu")
		(net "GND")
	)
	(via
		(at 337.299808 -47.250096)
		(size 0.4572)
		(drill 0.2032)
		(layers "F.Cu" "B.Cu")
		(net "GND")
	)
	(via
		(at 281.707082 -310.366664)
		(size 0.4572)
		(drill 0.2032)
		(layers "F.Cu" "B.Cu")
		(net "GND")
	)
	(via
		(at 336.034888 -400.858228)
		(size 0.4064)
		(drill 0.2032)
		(layers "F.Cu" "B.Cu")
		(net "GND")
	)
	(via
		(at 198.42353 -106.225848)
		(size 0.508)
		(drill 0.254)
		(layers "F.Cu" "B.Cu")
		(net "GND")
	)
	(via
		(at 56.045608 -167.30345)
		(size 0.49022)
		(drill 0.254)
		(layers "F.Cu" "B.Cu")
		(net "GND")
	)
	(via
		(at 276.373082 -249.166634)
		(size 0.4572)
		(drill 0.2032)
		(layers "F.Cu" "B.Cu")
		(net "GND")
	)
	(via
		(at 409.349956 -434.899562)
		(size 0.4572)
		(drill 0.2032)
		(layers "F.Cu" "B.Cu")
		(net "GND")
	)
	(via
		(at 137.014966 -240.667286)
		(size 0.4318)
		(drill 0.2032)
		(layers "F.Cu" "B.Cu")
		(net "GND")
	)
	(via
		(at 169.144442 -238.116618)
		(size 0.4572)
		(drill 0.2032)
		(layers "F.Cu" "B.Cu")
		(net "GND")
	)
	(via
		(at 285.150814 -246.616728)
		(size 0.4572)
		(drill 0.2032)
		(layers "F.Cu" "B.Cu")
		(net "GND")
	)
	(via
		(at 108.9787 -29.842714)
		(size 0.508)
		(drill 0.254)
		(layers "F.Cu" "B.Cu")
		(net "GND")
	)
	(via
		(at 272.273014 -268.71676)
		(size 0.4572)
		(drill 0.2032)
		(layers "F.Cu" "B.Cu")
		(net "GND")
	)
	(via
		(at 386.350002 -435.0512)
		(size 0.4572)
		(drill 0.2032)
		(layers "F.Cu" "B.Cu")
		(net "GND")
	)
	(via
		(at 121.617994 -280.778204)
		(size 0.4572)
		(drill 0.2032)
		(layers "F.Cu" "B.Cu")
		(net "GND")
	)
	(via
		(at 43.746674 -353.195128)
		(size 0.49022)
		(drill 0.254)
		(layers "F.Cu" "B.Cu")
		(net "GND")
	)
	(via
		(at 340.444328 -407.00452)
		(size 0.4064)
		(drill 0.2032)
		(layers "F.Cu" "B.Cu")
		(net "GND")
	)
	(via
		(at 150.867364 -58.41111)
		(size 0.508)
		(drill 0.254)
		(layers "F.Cu" "B.Cu")
		(net "GND")
	)
	(via
		(at 93.423994 -287.28924)
		(size 0.4572)
		(drill 0.2032)
		(layers "F.Cu" "B.Cu")
		(net "GND")
	)
	(via
		(at 117.823996 -250.33732)
		(size 0.4572)
		(drill 0.2032)
		(layers "F.Cu" "B.Cu")
		(net "GND")
	)
	(via
		(at 372.377462 -274.266914)
		(size 0.4572)
		(drill 0.2032)
		(layers "F.Cu" "B.Cu")
		(net "GND")
	)
	(via
		(at 205.180946 -223.666558)
		(size 0.4572)
		(drill 0.2032)
		(layers "F.Cu" "B.Cu")
		(net "GND")
	)
	(via
		(at 287.360614 -296.766742)
		(size 0.4572)
		(drill 0.2032)
		(layers "F.Cu" "B.Cu")
		(net "GND")
	)
	(via
		(at 169.352214 -194.766692)
		(size 0.4572)
		(drill 0.2032)
		(layers "F.Cu" "B.Cu")
		(net "GND")
	)
	(via
		(at 365.329216 -271.825212)
		(size 0.4572)
		(drill 0.2032)
		(layers "F.Cu" "B.Cu")
		(net "GND")
	)
	(via
		(at 420.736014 -263.616694)
		(size 0.4572)
		(drill 0.2032)
		(layers "F.Cu" "B.Cu")
		(net "GND")
	)
	(via
		(at 209.281014 -294.216582)
		(size 0.4572)
		(drill 0.2032)
		(layers "F.Cu" "B.Cu")
		(net "GND")
	)
	(via
		(at 420.736014 -267.016738)
		(size 0.4572)
		(drill 0.2032)
		(layers "F.Cu" "B.Cu")
		(net "GND")
	)
	(via
		(at 293.757096 -361.494324)
		(size 0.508)
		(drill 0.254)
		(layers "F.Cu" "B.Cu")
		(net "GND")
	)
	(via
		(at 411.047438 -404.51786)
		(size 0.4572)
		(drill 0.254)
		(layers "F.Cu" "B.Cu")
		(net "GND")
	)
	(via
		(at 167.461946 -217.716608)
		(size 0.4572)
		(drill 0.2032)
		(layers "F.Cu" "B.Cu")
		(net "GND")
	)
	(via
		(at 350.807274 -169.768012)
		(size 0.508)
		(drill 0.254)
		(layers "F.Cu" "B.Cu")
		(net "GND")
	)
	(via
		(at 209.281014 -221.116652)
		(size 0.4572)
		(drill 0.2032)
		(layers "F.Cu" "B.Cu")
		(net "GND")
	)
	(via
		(at 180.36032 -352.404172)
		(size 0.49022)
		(drill 0.254)
		(layers "F.Cu" "B.Cu")
		(net "GND")
	)
	(via
		(at 396.990062 -403.249892)
		(size 0.4572)
		(drill 0.254)
		(layers "F.Cu" "B.Cu")
		(net "GND")
	)
	(via
		(at 167.461946 -315.46673)
		(size 0.4572)
		(drill 0.2032)
		(layers "F.Cu" "B.Cu")
		(net "GND")
	)
	(via
		(at 135.605012 -236.597952)
		(size 0.4572)
		(drill 0.2032)
		(layers "F.Cu" "B.Cu")
		(net "GND")
	)
	(via
		(at 329.441048 -42.811446)
		(size 0.4572)
		(drill 0.2032)
		(layers "F.Cu" "B.Cu")
		(net "GND")
	)
	(via
		(at 43.520614 -306.96662)
		(size 0.4572)
		(drill 0.2032)
		(layers "F.Cu" "B.Cu")
		(net "GND")
	)
	(via
		(at 97.653348 -278.336502)
		(size 0.4572)
		(drill 0.2032)
		(layers "F.Cu" "B.Cu")
		(net "GND")
	)
	(via
		(at 471.03538 -74.264266)
		(size 0.508)
		(drill 0.254)
		(layers "F.Cu" "B.Cu")
		(net "GND")
	)
	(via
		(at 356.51821 -356.943406)
		(size 0.508)
		(drill 0.254)
		(layers "F.Cu" "B.Cu")
		(net "GND")
	)
	(via
		(at 228.463348 -135.47852)
		(size 0.508)
		(drill 0.254)
		(layers "F.Cu" "B.Cu")
		(net "GND")
	)
	(via
		(at 159.909256 -65.094358)
		(size 0.508)
		(drill 0.254)
		(layers "F.Cu" "B.Cu")
		(net "GND")
	)
	(via
		(at 261.285482 -295.916604)
		(size 0.4572)
		(drill 0.2032)
		(layers "F.Cu" "B.Cu")
		(net "GND")
	)
	(via
		(at 7.035546 -221.96679)
		(size 0.4572)
		(drill 0.2032)
		(layers "F.Cu" "B.Cu")
		(net "GND")
	)
	(via
		(at 95.30334 -253.10592)
		(size 0.4572)
		(drill 0.2032)
		(layers "F.Cu" "B.Cu")
		(net "GND")
	)
	(via
		(at 338.21878 -335.187036)
		(size 0.49022)
		(drill 0.254)
		(layers "F.Cu" "B.Cu")
		(net "GND")
	)
	(via
		(at 350.762062 -274.266914)
		(size 0.4572)
		(drill 0.2032)
		(layers "F.Cu" "B.Cu")
		(net "GND")
	)
	(via
		(at 54.508146 -296.766742)
		(size 0.4572)
		(drill 0.2032)
		(layers "F.Cu" "B.Cu")
		(net "GND")
	)
	(via
		(at 158.062422 -407.638504)
		(size 0.4572)
		(drill 0.254)
		(layers "F.Cu" "B.Cu")
		(net "GND")
	)
	(via
		(at 134.305548 -271.825212)
		(size 0.4572)
		(drill 0.2032)
		(layers "F.Cu" "B.Cu")
		(net "GND")
	)
	(via
		(at 331.484224 -339.624416)
		(size 0.508)
		(drill 0.254)
		(layers "F.Cu" "B.Cu")
		(net "GND")
	)
	(via
		(at 133.67512 -144.556988)
		(size 0.508)
		(drill 0.254)
		(layers "F.Cu" "B.Cu")
		(net "GND")
	)
	(via
		(at 289.250882 -288.266632)
		(size 0.4572)
		(drill 0.2032)
		(layers "F.Cu" "B.Cu")
		(net "GND")
	)
	(via
		(at 38.94709 -16.978376)
		(size 0.508)
		(drill 0.254)
		(layers "F.Cu" "B.Cu")
		(net "GND")
	)
	(via
		(at 254.975614 -231.316784)
		(size 0.4572)
		(drill 0.2032)
		(layers "F.Cu" "B.Cu")
		(net "GND")
	)
	(via
		(at 344.183462 -266.128246)
		(size 0.4572)
		(drill 0.2032)
		(layers "F.Cu" "B.Cu")
		(net "GND")
	)
	(via
		(at 371.437662 -267.755878)
		(size 0.4572)
		(drill 0.2032)
		(layers "F.Cu" "B.Cu")
		(net "GND")
	)
	(via
		(at 345.224608 -403.883876)
		(size 0.4064)
		(drill 0.2032)
		(layers "F.Cu" "B.Cu")
		(net "GND")
	)
	(via
		(at 309.992014 -197.316598)
		(size 0.4572)
		(drill 0.2032)
		(layers "F.Cu" "B.Cu")
		(net "GND")
	)
	(via
		(at 281.707082 -213.46668)
		(size 0.4572)
		(drill 0.2032)
		(layers "F.Cu" "B.Cu")
		(net "GND")
	)
	(via
		(at 95.773494 -283.219906)
		(size 0.4572)
		(drill 0.2032)
		(layers "F.Cu" "B.Cu")
		(net "GND")
	)
	(via
		(at 299.004482 -277.216616)
		(size 0.4572)
		(drill 0.2032)
		(layers "F.Cu" "B.Cu")
		(net "GND")
	)
	(via
		(at 285.150814 -217.716608)
		(size 0.4572)
		(drill 0.2032)
		(layers "F.Cu" "B.Cu")
		(net "GND")
	)
	(via
		(at 169.352214 -261.066788)
		(size 0.4572)
		(drill 0.2032)
		(layers "F.Cu" "B.Cu")
		(net "GND")
	)
	(via
		(at 29.186886 -166.351204)
		(size 0.508)
		(drill 0.254)
		(layers "F.Cu" "B.Cu")
		(net "GND")
	)
	(via
		(at 119.628666 -226.831144)
		(size 0.4572)
		(drill 0.2032)
		(layers "F.Cu" "B.Cu")
		(net "GND")
	)
	(via
		(at 438.033414 -292.516814)
		(size 0.4572)
		(drill 0.2032)
		(layers "F.Cu" "B.Cu")
		(net "GND")
	)
	(via
		(at 413.192214 -272.116804)
		(size 0.4572)
		(drill 0.2032)
		(layers "F.Cu" "B.Cu")
		(net "GND")
	)
	(via
		(at 359.86974 -57.257188)
		(size 0.508)
		(drill 0.254)
		(layers "F.Cu" "B.Cu")
		(net "GND")
	)
	(via
		(at 447.467482 -278.916638)
		(size 0.4572)
		(drill 0.2032)
		(layers "F.Cu" "B.Cu")
		(net "GND")
	)
	(via
		(at 122.917966 -245.55069)
		(size 0.4572)
		(drill 0.2032)
		(layers "F.Cu" "B.Cu")
		(net "GND")
	)
	(via
		(at 48.854614 -194.766692)
		(size 0.4572)
		(drill 0.2032)
		(layers "F.Cu" "B.Cu")
		(net "GND")
	)
	(via
		(at 317.250064 -430.147222)
		(size 0.4572)
		(drill 0.2032)
		(layers "F.Cu" "B.Cu")
		(net "GND")
	)
	(via
		(at 90.985086 -52.874926)
		(size 0.508)
		(drill 0.254)
		(layers "F.Cu" "B.Cu")
		(net "GND")
	)
	(via
		(at 329.54722 -403.249892)
		(size 0.4572)
		(drill 0.254)
		(layers "F.Cu" "B.Cu")
		(net "GND")
	)
	(via
		(at 414.756854 -7.215124)
		(size 0.508)
		(drill 0.254)
		(layers "F.Cu" "B.Cu")
		(net "GND")
	)
	(via
		(at 59.938158 -410.030168)
		(size 0.4064)
		(drill 0.2032)
		(layers "F.Cu" "B.Cu")
		(net "GND")
	)
	(via
		(at 381.305816 -281.59202)
		(size 0.4572)
		(drill 0.2032)
		(layers "F.Cu" "B.Cu")
		(net "GND")
	)
	(via
		(at 82.73669 -400.224244)
		(size 0.4572)
		(drill 0.254)
		(layers "F.Cu" "B.Cu")
		(net "GND")
	)
	(via
		(at 341.724234 -219.506038)
		(size 0.4572)
		(drill 0.2032)
		(layers "F.Cu" "B.Cu")
		(net "GND")
	)
	(via
		(at 97.073466 -223.575626)
		(size 0.4572)
		(drill 0.2032)
		(layers "F.Cu" "B.Cu")
		(net "GND")
	)
	(via
		(at 308.760622 -435.663848)
		(size 0.508)
		(drill 0.254)
		(layers "F.Cu" "B.Cu")
		(net "GND")
	)
	(via
		(at 13.345414 -282.316682)
		(size 0.4572)
		(drill 0.2032)
		(layers "F.Cu" "B.Cu")
		(net "GND")
	)
	(via
		(at 115.869466 -223.575626)
		(size 0.4572)
		(drill 0.2032)
		(layers "F.Cu" "B.Cu")
		(net "GND")
	)
	(via
		(at 41.310814 -219.41663)
		(size 0.4572)
		(drill 0.2032)
		(layers "F.Cu" "B.Cu")
		(net "GND")
	)
	(via
		(at 66.367914 -210.066636)
		(size 0.4572)
		(drill 0.2032)
		(layers "F.Cu" "B.Cu")
		(net "GND")
	)
	(via
		(at 67.42049 -401.492212)
		(size 0.4572)
		(drill 0.254)
		(layers "F.Cu" "B.Cu")
		(net "GND")
	)
	(via
		(at 63.942214 -232.166668)
		(size 0.4572)
		(drill 0.2032)
		(layers "F.Cu" "B.Cu")
		(net "GND")
	)
	(via
		(at 429.747172 -360.089704)
		(size 0.508)
		(drill 0.254)
		(layers "F.Cu" "B.Cu")
		(net "GND")
	)
	(via
		(at 286.260032 -387.147562)
		(size 0.508)
		(drill 0.254)
		(layers "F.Cu" "B.Cu")
		(net "GND")
	)
	(via
		(at 226.620832 -439.905394)
		(size 0.508)
		(drill 0.254)
		(layers "F.Cu" "B.Cu")
		(net "GND")
	)
	(via
		(at 216.824814 -262.76681)
		(size 0.4572)
		(drill 0.2032)
		(layers "F.Cu" "B.Cu")
		(net "GND")
	)
	(via
		(at 140.349986 -428.851314)
		(size 0.4572)
		(drill 0.2032)
		(layers "F.Cu" "B.Cu")
		(net "GND")
	)
	(via
		(at 109.601762 -95.667068)
		(size 0.508)
		(drill 0.254)
		(layers "F.Cu" "B.Cu")
		(net "GND")
	)
	(via
		(at 56.398414 -280.61666)
		(size 0.4572)
		(drill 0.2032)
		(layers "F.Cu" "B.Cu")
		(net "GND")
	)
	(via
		(at 323.267578 -339.05571)
		(size 0.508)
		(drill 0.254)
		(layers "F.Cu" "B.Cu")
		(net "GND")
	)
	(via
		(at 411.52318 -158.435548)
		(size 0.508)
		(drill 0.254)
		(layers "F.Cu" "B.Cu")
		(net "GND")
	)
	(via
		(at 138.34999 -425.547282)
		(size 0.4572)
		(drill 0.2032)
		(layers "F.Cu" "B.Cu")
		(net "GND")
	)
	(via
		(at 435.823614 -223.666558)
		(size 0.4572)
		(drill 0.2032)
		(layers "F.Cu" "B.Cu")
		(net "GND")
	)
	(via
		(at 347.363034 -235.783882)
		(size 0.4572)
		(drill 0.2032)
		(layers "F.Cu" "B.Cu")
		(net "GND")
	)
	(via
		(at 31.876746 -263.616694)
		(size 0.4572)
		(drill 0.2032)
		(layers "F.Cu" "B.Cu")
		(net "GND")
	)
	(via
		(at 31.876746 -199.01662)
		(size 0.4572)
		(drill 0.2032)
		(layers "F.Cu" "B.Cu")
		(net "GND")
	)
	(via
		(at 91.92641 -401.492212)
		(size 0.4572)
		(drill 0.254)
		(layers "F.Cu" "B.Cu")
		(net "GND")
	)
	(via
		(at 446.915286 -74.278236)
		(size 0.508)
		(drill 0.254)
		(layers "F.Cu" "B.Cu")
		(net "GND")
	)
	(via
		(at 67.507866 -407.638504)
		(size 0.4572)
		(drill 0.254)
		(layers "F.Cu" "B.Cu")
		(net "GND")
	)
	(via
		(at 302.664114 -292.516814)
		(size 0.4572)
		(drill 0.2032)
		(layers "F.Cu" "B.Cu")
		(net "GND")
	)
	(via
		(at 28.433014 -200.716642)
		(size 0.4572)
		(drill 0.2032)
		(layers "F.Cu" "B.Cu")
		(net "GND")
	)
	(via
		(at 159.918146 -214.316564)
		(size 0.4572)
		(drill 0.2032)
		(layers "F.Cu" "B.Cu")
		(net "GND")
	)
	(via
		(at 268.829282 -210.066636)
		(size 0.4572)
		(drill 0.2032)
		(layers "F.Cu" "B.Cu")
		(net "GND")
	)
	(via
		(at 373.787162 -271.825212)
		(size 0.4572)
		(drill 0.2032)
		(layers "F.Cu" "B.Cu")
		(net "GND")
	)
	(via
		(at 276.373082 -230.466646)
		(size 0.4572)
		(drill 0.2032)
		(layers "F.Cu" "B.Cu")
		(net "GND")
	)
	(via
		(at 120.97639 -252.609604)
		(size 0.4572)
		(drill 0.2032)
		(layers "F.Cu" "B.Cu")
		(net "GND")
	)
	(via
		(at 91.544394 -266.128246)
		(size 0.4572)
		(drill 0.2032)
		(layers "F.Cu" "B.Cu")
		(net "GND")
	)
	(via
		(at 128.086866 -226.831144)
		(size 0.4572)
		(drill 0.2032)
		(layers "F.Cu" "B.Cu")
		(net "GND")
	)
	(via
		(at 430.489614 -238.966756)
		(size 0.4572)
		(drill 0.2032)
		(layers "F.Cu" "B.Cu")
		(net "GND")
	)
	(via
		(at 351.085404 -332.56601)
		(size 0.49022)
		(drill 0.254)
		(layers "F.Cu" "B.Cu")
		(net "GND")
	)
	(via
		(at 120.94972 -240.70437)
		(size 0.4572)
		(drill 0.2032)
		(layers "F.Cu" "B.Cu")
		(net "GND")
	)
	(via
		(at 102.821994 -266.128246)
		(size 0.4572)
		(drill 0.2032)
		(layers "F.Cu" "B.Cu")
		(net "GND")
	)
	(via
		(at 127.430022 -410.664152)
		(size 0.4572)
		(drill 0.254)
		(layers "F.Cu" "B.Cu")
		(net "GND")
	)
	(via
		(at 91.347798 -250.66117)
		(size 0.6604)
		(drill 0.3302)
		(layers "F.Cu" "B.Cu")
		(net "GND")
	)
	(via
		(at 66.152014 -250.866656)
		(size 0.4572)
		(drill 0.2032)
		(layers "F.Cu" "B.Cu")
		(net "GND")
	)
	(via
		(at 445.577214 -244.916706)
		(size 0.4572)
		(drill 0.2032)
		(layers "F.Cu" "B.Cu")
		(net "GND")
	)
	(via
		(at 430.489614 -270.416782)
		(size 0.4572)
		(drill 0.2032)
		(layers "F.Cu" "B.Cu")
		(net "GND")
	)
	(via
		(at 201.737214 -310.366664)
		(size 0.4572)
		(drill 0.2032)
		(layers "F.Cu" "B.Cu")
		(net "GND")
	)
	(via
		(at 52.298346 -304.416714)
		(size 0.4572)
		(drill 0.2032)
		(layers "F.Cu" "B.Cu")
		(net "GND")
	)
	(via
		(at 59.57697 -407.638504)
		(size 0.4572)
		(drill 0.254)
		(layers "F.Cu" "B.Cu")
		(net "GND")
	)
	(via
		(at 129.017268 -366.093248)
		(size 0.508)
		(drill 0.254)
		(layers "F.Cu" "B.Cu")
		(net "GND")
	)
	(via
		(at 129.606548 -266.941808)
		(size 0.4572)
		(drill 0.2032)
		(layers "F.Cu" "B.Cu")
		(net "GND")
	)
	(via
		(at 20.889214 -244.066568)
		(size 0.4572)
		(drill 0.2032)
		(layers "F.Cu" "B.Cu")
		(net "GND")
	)
	(via
		(at 374.617234 -227.64496)
		(size 0.4572)
		(drill 0.2032)
		(layers "F.Cu" "B.Cu")
		(net "GND")
	)
	(via
		(at 35.976814 -244.066568)
		(size 0.4572)
		(drill 0.2032)
		(layers "F.Cu" "B.Cu")
		(net "GND")
	)
	(via
		(at 48.854614 -314.616592)
		(size 0.4572)
		(drill 0.2032)
		(layers "F.Cu" "B.Cu")
		(net "GND")
	)
	(via
		(at 66.87312 -8.969248)
		(size 0.508)
		(drill 0.254)
		(layers "F.Cu" "B.Cu")
		(net "GND")
	)
	(via
		(at 419.75786 -310.366664)
		(size 0.4572)
		(drill 0.2032)
		(layers "F.Cu" "B.Cu")
		(net "GND")
	)
	(via
		(at 91.92641 -403.249892)
		(size 0.4572)
		(drill 0.254)
		(layers "F.Cu" "B.Cu")
		(net "GND")
	)
	(via
		(at 382.03505 -403.883876)
		(size 0.4064)
		(drill 0.2032)
		(layers "F.Cu" "B.Cu")
		(net "GND")
	)
	(via
		(at 177.315876 -345.934538)
		(size 0.508)
		(drill 0.254)
		(layers "F.Cu" "B.Cu")
		(net "GND")
	)
	(via
		(at 300.022514 -220.266768)
		(size 0.4572)
		(drill 0.2032)
		(layers "F.Cu" "B.Cu")
		(net "GND")
	)
	(via
		(at 409.748482 -202.416664)
		(size 0.4572)
		(drill 0.2032)
		(layers "F.Cu" "B.Cu")
		(net "GND")
	)
	(via
		(at 239.99952 -58.597038)
		(size 0.508)
		(drill 0.254)
		(layers "F.Cu" "B.Cu")
		(net "GND")
	)
	(via
		(at 195.427346 -210.916774)
		(size 0.4572)
		(drill 0.2032)
		(layers "F.Cu" "B.Cu")
		(net "GND")
	)
	(via
		(at 119.957342 -403.249892)
		(size 0.4572)
		(drill 0.254)
		(layers "F.Cu" "B.Cu")
		(net "GND")
	)
	(via
		(at 176.896014 -295.916604)
		(size 0.4572)
		(drill 0.2032)
		(layers "F.Cu" "B.Cu")
		(net "GND")
	)
	(via
		(at 136.075166 -216.25052)
		(size 0.4572)
		(drill 0.2032)
		(layers "F.Cu" "B.Cu")
		(net "GND")
	)
	(via
		(at 399.349976 -429.147224)
		(size 0.4572)
		(drill 0.2032)
		(layers "F.Cu" "B.Cu")
		(net "GND")
	)
	(via
		(at 374.257062 -256.361438)
		(size 0.4572)
		(drill 0.2032)
		(layers "F.Cu" "B.Cu")
		(net "GND")
	)
	(via
		(at 349.678244 -355.538532)
		(size 0.508)
		(drill 0.254)
		(layers "F.Cu" "B.Cu")
		(net "GND")
	)
	(via
		(at 412.728664 -6.586474)
		(size 0.508)
		(drill 0.254)
		(layers "F.Cu" "B.Cu")
		(net "GND")
	)
	(via
		(at 445.577214 -246.616728)
		(size 0.4572)
		(drill 0.2032)
		(layers "F.Cu" "B.Cu")
		(net "GND")
	)
	(via
		(at 450.084952 -394.876274)
		(size 0.6604)
		(drill 0.3302)
		(layers "F.Cu" "B.Cu")
		(net "GND")
	)
	(via
		(at 358.170734 -239.853216)
		(size 0.4572)
		(drill 0.2032)
		(layers "F.Cu" "B.Cu")
		(net "GND")
	)
	(via
		(at 24.332946 -287.416748)
		(size 0.4572)
		(drill 0.2032)
		(layers "F.Cu" "B.Cu")
		(net "GND")
	)
	(via
		(at 383.727452 -341.766906)
		(size 0.49022)
		(drill 0.254)
		(layers "F.Cu" "B.Cu")
		(net "GND")
	)
	(via
		(at 291.460682 -245.76659)
		(size 0.4572)
		(drill 0.2032)
		(layers "F.Cu" "B.Cu")
		(net "GND")
	)
	(via
		(at 415.09569 -407.00452)
		(size 0.4064)
		(drill 0.2032)
		(layers "F.Cu" "B.Cu")
		(net "GND")
	)
	(via
		(at 144.97304 -114.73434)
		(size 0.508)
		(drill 0.254)
		(layers "F.Cu" "B.Cu")
		(net "GND")
	)
	(via
		(at 360.617516 -333.355188)
		(size 0.49022)
		(drill 0.254)
		(layers "F.Cu" "B.Cu")
		(net "GND")
	)
	(via
		(at 297.265598 -154.261058)
		(size 0.508)
		(drill 0.254)
		(layers "F.Cu" "B.Cu")
		(net "GND")
	)
	(via
		(at 165.252146 -195.616576)
		(size 0.4572)
		(drill 0.2032)
		(layers "F.Cu" "B.Cu")
		(net "GND")
	)
	(via
		(at 44.754546 -289.11677)
		(size 0.4572)
		(drill 0.2032)
		(layers "F.Cu" "B.Cu")
		(net "GND")
	)
	(via
		(at 226.967288 -126.012956)
		(size 0.508)
		(drill 0.254)
		(layers "F.Cu" "B.Cu")
		(net "GND")
	)
	(via
		(at 346.667836 -400.200368)
		(size 0.4572)
		(drill 0.254)
		(layers "F.Cu" "B.Cu")
		(net "GND")
	)
	(via
		(at 136.349994 -427.699678)
		(size 0.4572)
		(drill 0.2032)
		(layers "F.Cu" "B.Cu")
		(net "GND")
	)
	(via
		(at 447.467482 -314.616592)
		(size 0.4572)
		(drill 0.2032)
		(layers "F.Cu" "B.Cu")
		(net "GND")
	)
	(via
		(at 346.063062 -256.361438)
		(size 0.4572)
		(drill 0.2032)
		(layers "F.Cu" "B.Cu")
		(net "GND")
	)
	(via
		(at 393.926822 -400.224244)
		(size 0.4572)
		(drill 0.254)
		(layers "F.Cu" "B.Cu")
		(net "GND")
	)
	(via
		(at 336.195162 -268.569694)
		(size 0.4572)
		(drill 0.2032)
		(layers "F.Cu" "B.Cu")
		(net "GND")
	)
	(via
		(at 399.77949 -407.00452)
		(size 0.4064)
		(drill 0.2032)
		(layers "F.Cu" "B.Cu")
		(net "GND")
	)
	(via
		(at 187.883546 -301.866808)
		(size 0.4572)
		(drill 0.2032)
		(layers "F.Cu" "B.Cu")
		(net "GND")
	)
	(via
		(at 405.349964 -428.851314)
		(size 0.4572)
		(drill 0.2032)
		(layers "F.Cu" "B.Cu")
		(net "GND")
	)
	(via
		(at 320.444876 -406.370536)
		(size 0.4572)
		(drill 0.254)
		(layers "F.Cu" "B.Cu")
		(net "GND")
	)
	(via
		(at 394.349986 -425.547282)
		(size 0.4572)
		(drill 0.2032)
		(layers "F.Cu" "B.Cu")
		(net "GND")
	)
	(via
		(at 304.338482 -226.216718)
		(size 0.4572)
		(drill 0.2032)
		(layers "F.Cu" "B.Cu")
		(net "GND")
	)
	(via
		(at 101.882194 -274.266914)
		(size 0.4572)
		(drill 0.2032)
		(layers "F.Cu" "B.Cu")
		(net "GND")
	)
	(via
		(at 401.857718 -401.492212)
		(size 0.4572)
		(drill 0.254)
		(layers "F.Cu" "B.Cu")
		(net "GND")
	)
	(via
		(at 140.349986 -430.147222)
		(size 0.4572)
		(drill 0.2032)
		(layers "F.Cu" "B.Cu")
		(net "GND")
	)
	(via
		(at 381.305562 -255.547622)
		(size 0.4572)
		(drill 0.2032)
		(layers "F.Cu" "B.Cu")
		(net "GND")
	)
	(via
		(at 277.607014 -276.366732)
		(size 0.4572)
		(drill 0.2032)
		(layers "F.Cu" "B.Cu")
		(net "GND")
	)
	(via
		(at 85.325712 -232.528364)
		(size 0.4572)
		(drill 0.2032)
		(layers "F.Cu" "B.Cu")
		(net "GND")
	)
	(via
		(at 344.543634 -226.017328)
		(size 0.4572)
		(drill 0.2032)
		(layers "F.Cu" "B.Cu")
		(net "GND")
	)
	(via
		(at 164.018214 -282.316682)
		(size 0.4572)
		(drill 0.2032)
		(layers "F.Cu" "B.Cu")
		(net "GND")
	)
	(via
		(at 190.093346 -240.666778)
		(size 0.4572)
		(drill 0.2032)
		(layers "F.Cu" "B.Cu")
		(net "GND")
	)
	(via
		(at 139.321794 -410.030168)
		(size 0.4064)
		(drill 0.2032)
		(layers "F.Cu" "B.Cu")
		(net "GND")
	)
	(via
		(at 56.398414 -299.316648)
		(size 0.4572)
		(drill 0.2032)
		(layers "F.Cu" "B.Cu")
		(net "GND")
	)
	(via
		(at 433.117752 -323.429376)
		(size 0.4572)
		(drill 0.2032)
		(layers "F.Cu" "B.Cu")
		(net "GND")
	)
	(via
		(at 9.245346 -301.866808)
		(size 0.4572)
		(drill 0.2032)
		(layers "F.Cu" "B.Cu")
		(net "GND")
	)
	(via
		(at 449.677282 -267.866622)
		(size 0.4572)
		(drill 0.2032)
		(layers "F.Cu" "B.Cu")
		(net "GND")
	)
	(via
		(at 292.694614 -306.116736)
		(size 0.4572)
		(drill 0.2032)
		(layers "F.Cu" "B.Cu")
		(net "GND")
	)
	(via
		(at 292.694614 -203.266802)
		(size 0.4572)
		(drill 0.2032)
		(layers "F.Cu" "B.Cu")
		(net "GND")
	)
	(via
		(at 137.108438 -341.766906)
		(size 0.49022)
		(drill 0.254)
		(layers "F.Cu" "B.Cu")
		(net "GND")
	)
	(via
		(at 22.419056 -6.090412)
		(size 0.508)
		(drill 0.254)
		(layers "F.Cu" "B.Cu")
		(net "GND")
	)
	(via
		(at 340.894416 -273.453098)
		(size 0.4572)
		(drill 0.2032)
		(layers "F.Cu" "B.Cu")
		(net "GND")
	)
	(via
		(at 254.975614 -292.516814)
		(size 0.4572)
		(drill 0.2032)
		(layers "F.Cu" "B.Cu")
		(net "GND")
	)
	(via
		(at 184.439814 -230.466646)
		(size 0.4572)
		(drill 0.2032)
		(layers "F.Cu" "B.Cu")
		(net "GND")
	)
	(via
		(at 135.424418 -339.60435)
		(size 0.6604)
		(drill 0.3302)
		(layers "F.Cu" "B.Cu")
		(net "GND")
	)
	(via
		(at 22.69109 -17.61236)
		(size 0.508)
		(drill 0.254)
		(layers "F.Cu" "B.Cu")
		(net "GND")
	)
	(via
		(at 450.911214 -287.416748)
		(size 0.4572)
		(drill 0.2032)
		(layers "F.Cu" "B.Cu")
		(net "GND")
	)
	(via
		(at 172.955712 -107.775502)
		(size 0.4572)
		(drill 0.254)
		(layers "F.Cu" "B.Cu")
		(net "GND")
	)
	(via
		(at 52.298346 -246.616728)
		(size 0.4572)
		(drill 0.2032)
		(layers "F.Cu" "B.Cu")
		(net "GND")
	)
	(via
		(at 35.976814 -258.516628)
		(size 0.4572)
		(drill 0.2032)
		(layers "F.Cu" "B.Cu")
		(net "GND")
	)
	(via
		(at 353.581716 -279.150318)
		(size 0.4572)
		(drill 0.2032)
		(layers "F.Cu" "B.Cu")
		(net "GND")
	)
	(via
		(at 359.579926 -214.622634)
		(size 0.4572)
		(drill 0.2032)
		(layers "F.Cu" "B.Cu")
		(net "GND")
	)
	(via
		(at 294.904414 -296.766742)
		(size 0.4572)
		(drill 0.2032)
		(layers "F.Cu" "B.Cu")
		(net "GND")
	)
	(via
		(at 447.467482 -282.316682)
		(size 0.4572)
		(drill 0.2032)
		(layers "F.Cu" "B.Cu")
		(net "GND")
	)
	(via
		(at 450.911214 -240.666778)
		(size 0.4572)
		(drill 0.2032)
		(layers "F.Cu" "B.Cu")
		(net "GND")
	)
	(via
		(at 180.838602 -355.538278)
		(size 0.49022)
		(drill 0.254)
		(layers "F.Cu" "B.Cu")
		(net "GND")
	)
	(via
		(at 0.76454 -16.080232)
		(size 0.508)
		(drill 0.254)
		(layers "F.Cu" "B.Cu")
		(net "GND")
	)
	(via
		(at 28.638246 -396.390876)
		(size 0.508)
		(drill 0.254)
		(layers "F.Cu" "B.Cu")
		(net "GND")
	)
	(via
		(at 300.022514 -292.516814)
		(size 0.4572)
		(drill 0.2032)
		(layers "F.Cu" "B.Cu")
		(net "GND")
	)
	(via
		(at 310.893968 -410.030168)
		(size 0.4064)
		(drill 0.2032)
		(layers "F.Cu" "B.Cu")
		(net "GND")
	)
	(via
		(at 443.367414 -227.066602)
		(size 0.4572)
		(drill 0.2032)
		(layers "F.Cu" "B.Cu")
		(net "GND")
	)
	(via
		(at 449.677282 -241.516662)
		(size 0.4572)
		(drill 0.2032)
		(layers "F.Cu" "B.Cu")
		(net "GND")
	)
	(via
		(at 257.185414 -278.066754)
		(size 0.4572)
		(drill 0.2032)
		(layers "F.Cu" "B.Cu")
		(net "GND")
	)
	(via
		(at 28.27909 -17.61236)
		(size 0.508)
		(drill 0.254)
		(layers "F.Cu" "B.Cu")
		(net "GND")
	)
	(via
		(at 405.648414 -281.466798)
		(size 0.4572)
		(drill 0.2032)
		(layers "F.Cu" "B.Cu")
		(net "GND")
	)
	(via
		(at 299.004482 -204.116686)
		(size 0.4572)
		(drill 0.2032)
		(layers "F.Cu" "B.Cu")
		(net "GND")
	)
	(via
		(at 62.051946 -268.71676)
		(size 0.4572)
		(drill 0.2032)
		(layers "F.Cu" "B.Cu")
		(net "GND")
	)
	(via
		(at 94.833948 -257.175254)
		(size 0.4572)
		(drill 0.2032)
		(layers "F.Cu" "B.Cu")
		(net "GND")
	)
	(via
		(at 300.238414 -216.016586)
		(size 0.4572)
		(drill 0.2032)
		(layers "F.Cu" "B.Cu")
		(net "GND")
	)
	(via
		(at 464.764882 -202.416664)
		(size 0.4572)
		(drill 0.2032)
		(layers "F.Cu" "B.Cu")
		(net "GND")
	)
	(via
		(at 209.281014 -280.61666)
		(size 0.4572)
		(drill 0.2032)
		(layers "F.Cu" "B.Cu")
		(net "GND")
	)
	(via
		(at 378.956062 -269.38351)
		(size 0.4572)
		(drill 0.2032)
		(layers "F.Cu" "B.Cu")
		(net "GND")
	)
	(via
		(at 122.562366 -410.664152)
		(size 0.4572)
		(drill 0.254)
		(layers "F.Cu" "B.Cu")
		(net "GND")
	)
	(via
		(at 378.84608 -233.34218)
		(size 0.4572)
		(drill 0.2032)
		(layers "F.Cu" "B.Cu")
		(net "GND")
	)
	(via
		(at 262.519414 -285.716726)
		(size 0.4572)
		(drill 0.2032)
		(layers "F.Cu" "B.Cu")
		(net "GND")
	)
	(via
		(at 161.808414 -261.066788)
		(size 0.4572)
		(drill 0.2032)
		(layers "F.Cu" "B.Cu")
		(net "GND")
	)
	(via
		(at 127.147066 -213.732618)
		(size 0.4572)
		(drill 0.2032)
		(layers "F.Cu" "B.Cu")
		(net "GND")
	)
	(via
		(at 382.245616 -263.686544)
		(size 0.4572)
		(drill 0.2032)
		(layers "F.Cu" "B.Cu")
		(net "GND")
	)
	(via
		(at 149.945598 -45.111416)
		(size 0.508)
		(drill 0.254)
		(layers "F.Cu" "B.Cu")
		(net "GND")
	)
	(via
		(at 287.360614 -265.316716)
		(size 0.4572)
		(drill 0.2032)
		(layers "F.Cu" "B.Cu")
		(net "GND")
	)
	(via
		(at 26.47188 -101.818948)
		(size 0.508)
		(drill 0.254)
		(layers "F.Cu" "B.Cu")
		(net "GND")
	)
	(via
		(at 184.439814 -216.866724)
		(size 0.4572)
		(drill 0.2032)
		(layers "F.Cu" "B.Cu")
		(net "GND")
	)
	(via
		(at 61.250068 -437.34736)
		(size 0.4572)
		(drill 0.2032)
		(layers "F.Cu" "B.Cu")
		(net "GND")
	)
	(via
		(at 31.147004 -9.424924)
		(size 0.508)
		(drill 0.254)
		(layers "F.Cu" "B.Cu")
		(net "GND")
	)
	(via
		(at 194.193414 -267.866622)
		(size 0.4572)
		(drill 0.2032)
		(layers "F.Cu" "B.Cu")
		(net "GND")
	)
	(via
		(at 50.557938 -108.871004)
		(size 0.508)
		(drill 0.254)
		(layers "F.Cu" "B.Cu")
		(net "GND")
	)
	(via
		(at 429.305466 -6.07949)
		(size 0.508)
		(drill 0.254)
		(layers "F.Cu" "B.Cu")
		(net "GND")
	)
	(via
		(at 186.649614 -196.466714)
		(size 0.4572)
		(drill 0.2032)
		(layers "F.Cu" "B.Cu")
		(net "GND")
	)
	(via
		(at 64.05753 -36.65728)
		(size 0.508)
		(drill 0.254)
		(layers "F.Cu" "B.Cu")
		(net "GND")
	)
	(via
		(at 439.923682 -207.51673)
		(size 0.4572)
		(drill 0.2032)
		(layers "F.Cu" "B.Cu")
		(net "GND")
	)
	(via
		(at 268.739112 -62.615572)
		(size 0.508)
		(drill 0.254)
		(layers "F.Cu" "B.Cu")
		(net "GND")
	)
	(via
		(at 66.392298 -33.980882)
		(size 0.508)
		(drill 0.254)
		(layers "F.Cu" "B.Cu")
		(net "GND")
	)
	(via
		(at 134.067042 -38.049708)
		(size 0.508)
		(drill 0.254)
		(layers "F.Cu" "B.Cu")
		(net "GND")
	)
	(via
		(at 378.697998 -407.638504)
		(size 0.4572)
		(drill 0.254)
		(layers "F.Cu" "B.Cu")
		(net "GND")
	)
	(via
		(at 462.555082 -305.266598)
		(size 0.4572)
		(drill 0.2032)
		(layers "F.Cu" "B.Cu")
		(net "GND")
	)
	(via
		(at 320.7512 -25.6794)
		(size 0.508)
		(drill 0.254)
		(layers "F.Cu" "B.Cu")
		(net "GND")
	)
	(via
		(at 190.093346 -234.716574)
		(size 0.4572)
		(drill 0.2032)
		(layers "F.Cu" "B.Cu")
		(net "GND")
	)
	(via
		(at 71.250048 -432.747166)
		(size 0.4572)
		(drill 0.2032)
		(layers "F.Cu" "B.Cu")
		(net "GND")
	)
	(via
		(at 89.224358 -400.858228)
		(size 0.4064)
		(drill 0.2032)
		(layers "F.Cu" "B.Cu")
		(net "GND")
	)
	(via
		(at 88.145366 -221.133924)
		(size 0.4572)
		(drill 0.2032)
		(layers "F.Cu" "B.Cu")
		(net "GND")
	)
	(via
		(at 170.801284 -323.434456)
		(size 0.4572)
		(drill 0.2032)
		(layers "F.Cu" "B.Cu")
		(net "GND")
	)
	(via
		(at 80.25003 -437.49976)
		(size 0.4572)
		(drill 0.2032)
		(layers "F.Cu" "B.Cu")
		(net "GND")
	)
	(via
		(at 266.619482 -204.116686)
		(size 0.4572)
		(drill 0.2032)
		(layers "F.Cu" "B.Cu")
		(net "GND")
	)
	(via
		(at 342.303862 -264.50036)
		(size 0.4572)
		(drill 0.2032)
		(layers "F.Cu" "B.Cu")
		(net "GND")
	)
	(via
		(at 179.69992 -352.404172)
		(size 0.49022)
		(drill 0.254)
		(layers "F.Cu" "B.Cu")
		(net "GND")
	)
	(via
		(at 194.193414 -238.116618)
		(size 0.4572)
		(drill 0.2032)
		(layers "F.Cu" "B.Cu")
		(net "GND")
	)
	(via
		(at 259.075682 -258.516628)
		(size 0.4572)
		(drill 0.2032)
		(layers "F.Cu" "B.Cu")
		(net "GND")
	)
	(via
		(at 86.265766 -226.017328)
		(size 0.4572)
		(drill 0.2032)
		(layers "F.Cu" "B.Cu")
		(net "GND")
	)
	(via
		(at 338.544916 -257.98907)
		(size 0.4572)
		(drill 0.2032)
		(layers "F.Cu" "B.Cu")
		(net "GND")
	)
	(via
		(at 120.208548 -271.825212)
		(size 0.4572)
		(drill 0.2032)
		(layers "F.Cu" "B.Cu")
		(net "GND")
	)
	(via
		(at 113.629694 -270.19758)
		(size 0.4572)
		(drill 0.2032)
		(layers "F.Cu" "B.Cu")
		(net "GND")
	)
	(via
		(at 350.652334 -217.064336)
		(size 0.4572)
		(drill 0.2032)
		(layers "F.Cu" "B.Cu")
		(net "GND")
	)
	(via
		(at 443.357 -49.240948)
		(size 0.508)
		(drill 0.254)
		(layers "F.Cu" "B.Cu")
		(net "GND")
	)
	(via
		(at 83.54441 -339.624416)
		(size 0.508)
		(drill 0.254)
		(layers "F.Cu" "B.Cu")
		(net "GND")
	)
	(via
		(at 370.497862 -266.128246)
		(size 0.4572)
		(drill 0.2032)
		(layers "F.Cu" "B.Cu")
		(net "GND")
	)
	(via
		(at 147.068286 -407.638504)
		(size 0.4572)
		(drill 0.254)
		(layers "F.Cu" "B.Cu")
		(net "GND")
	)
	(via
		(at 430.489614 -289.11677)
		(size 0.4572)
		(drill 0.2032)
		(layers "F.Cu" "B.Cu")
		(net "GND")
	)
	(via
		(at 134.195566 -222.761556)
		(size 0.4572)
		(drill 0.2032)
		(layers "F.Cu" "B.Cu")
		(net "GND")
	)
	(via
		(at 182.549546 -217.716608)
		(size 0.4572)
		(drill 0.2032)
		(layers "F.Cu" "B.Cu")
		(net "GND")
	)
	(via
		(at 171.562014 -297.616626)
		(size 0.4572)
		(drill 0.2032)
		(layers "F.Cu" "B.Cu")
		(net "GND")
	)
	(via
		(at 155.20162 -47.846488)
		(size 0.508)
		(drill 0.254)
		(layers "F.Cu" "B.Cu")
		(net "GND")
	)
	(via
		(at 44.754546 -304.416714)
		(size 0.4572)
		(drill 0.2032)
		(layers "F.Cu" "B.Cu")
		(net "GND")
	)
	(via
		(at 272.273014 -212.616796)
		(size 0.4572)
		(drill 0.2032)
		(layers "F.Cu" "B.Cu")
		(net "GND")
	)
	(via
		(at 199.527414 -282.316682)
		(size 0.4572)
		(drill 0.2032)
		(layers "F.Cu" "B.Cu")
		(net "GND")
	)
	(via
		(at 311.882282 -267.866622)
		(size 0.4572)
		(drill 0.2032)
		(layers "F.Cu" "B.Cu")
		(net "GND")
	)
	(via
		(at 187.883546 -261.916672)
		(size 0.4572)
		(drill 0.2032)
		(layers "F.Cu" "B.Cu")
		(net "GND")
	)
	(via
		(at 435.823614 -317.166752)
		(size 0.4572)
		(drill 0.2032)
		(layers "F.Cu" "B.Cu")
		(net "GND")
	)
	(via
		(at 442.133482 -286.56661)
		(size 0.4572)
		(drill 0.2032)
		(layers "F.Cu" "B.Cu")
		(net "GND")
	)
	(via
		(at 285.150814 -285.716726)
		(size 0.4572)
		(drill 0.2032)
		(layers "F.Cu" "B.Cu")
		(net "GND")
	)
	(via
		(at 37.210746 -276.366732)
		(size 0.4572)
		(drill 0.2032)
		(layers "F.Cu" "B.Cu")
		(net "GND")
	)
	(via
		(at 462.555082 -230.466646)
		(size 0.4572)
		(drill 0.2032)
		(layers "F.Cu" "B.Cu")
		(net "GND")
	)
	(via
		(at 49.04105 -401.492212)
		(size 0.4572)
		(drill 0.254)
		(layers "F.Cu" "B.Cu")
		(net "GND")
	)
	(via
		(at 115.399312 -216.25052)
		(size 0.4572)
		(drill 0.2032)
		(layers "F.Cu" "B.Cu")
		(net "GND")
	)
	(via
		(at 352.214942 -295.02608)
		(size 0.508)
		(drill 0.254)
		(layers "F.Cu" "B.Cu")
		(net "GND")
	)
	(via
		(at 29.666946 -227.066602)
		(size 0.4572)
		(drill 0.2032)
		(layers "F.Cu" "B.Cu")
		(net "GND")
	)
	(via
		(at 462.555082 -294.216582)
		(size 0.4572)
		(drill 0.2032)
		(layers "F.Cu" "B.Cu")
		(net "GND")
	)
	(via
		(at 58.513218 -170.689524)
		(size 0.508)
		(drill 0.254)
		(layers "F.Cu" "B.Cu")
		(net "GND")
	)
	(via
		(at 371.764306 -166.030148)
		(size 0.508)
		(drill 0.254)
		(layers "F.Cu" "B.Cu")
		(net "GND")
	)
	(via
		(at 285.413196 -361.374944)
		(size 0.508)
		(drill 0.254)
		(layers "F.Cu" "B.Cu")
		(net "GND")
	)
	(via
		(at 268.829282 -267.866622)
		(size 0.4572)
		(drill 0.2032)
		(layers "F.Cu" "B.Cu")
		(net "GND")
	)
	(via
		(at 203.745084 -323.434456)
		(size 0.4572)
		(drill 0.2032)
		(layers "F.Cu" "B.Cu")
		(net "GND")
	)
	(via
		(at 312.01868 -14.950948)
		(size 0.508)
		(drill 0.254)
		(layers "F.Cu" "B.Cu")
		(net "GND")
	)
	(via
		(at 199.527414 -213.46668)
		(size 0.4572)
		(drill 0.2032)
		(layers "F.Cu" "B.Cu")
		(net "GND")
	)
	(via
		(at 98.60788 -414.376616)
		(size 0.508)
		(drill 0.254)
		(layers "F.Cu" "B.Cu")
		(net "GND")
	)
	(via
		(at 134.912354 -400.858228)
		(size 0.4064)
		(drill 0.2032)
		(layers "F.Cu" "B.Cu")
		(net "GND")
	)
	(via
		(at 304.338482 -241.516662)
		(size 0.4572)
		(drill 0.2032)
		(layers "F.Cu" "B.Cu")
		(net "GND")
	)
	(via
		(at 109.870494 -275.08073)
		(size 0.4572)
		(drill 0.2032)
		(layers "F.Cu" "B.Cu")
		(net "GND")
	)
	(via
		(at 130.906012 -233.34218)
		(size 0.4572)
		(drill 0.2032)
		(layers "F.Cu" "B.Cu")
		(net "GND")
	)
	(via
		(at 300.022514 -234.716574)
		(size 0.4572)
		(drill 0.2032)
		(layers "F.Cu" "B.Cu")
		(net "GND")
	)
	(via
		(at 372.286784 -331.08392)
		(size 0.508)
		(drill 0.254)
		(layers "F.Cu" "B.Cu")
		(net "GND")
	)
	(via
		(at 202.0824 -102.235)
		(size 0.508)
		(drill 0.254)
		(layers "F.Cu" "B.Cu")
		(net "GND")
	)
	(via
		(at 382.245616 -268.569694)
		(size 0.4572)
		(drill 0.2032)
		(layers "F.Cu" "B.Cu")
		(net "GND")
	)
	(via
		(at 131.015994 -259.616956)
		(size 0.4572)
		(drill 0.2032)
		(layers "F.Cu" "B.Cu")
		(net "GND")
	)
	(via
		(at 335.255362 -273.453098)
		(size 0.4318)
		(drill 0.2032)
		(layers "F.Cu" "B.Cu")
		(net "GND")
	)
	(via
		(at 56.971946 -400.224244)
		(size 0.4572)
		(drill 0.254)
		(layers "F.Cu" "B.Cu")
		(net "GND")
	)
	(via
		(at 309.992014 -304.416714)
		(size 0.4572)
		(drill 0.2032)
		(layers "F.Cu" "B.Cu")
		(net "GND")
	)
	(via
		(at 24.332946 -197.316598)
		(size 0.4572)
		(drill 0.2032)
		(layers "F.Cu" "B.Cu")
		(net "GND")
	)
	(via
		(at 139.516612 -241.203226)
		(size 0.4572)
		(drill 0.2032)
		(layers "F.Cu" "B.Cu")
		(net "GND")
	)
	(via
		(at 128.35001 -430.147222)
		(size 0.4572)
		(drill 0.2032)
		(layers "F.Cu" "B.Cu")
		(net "GND")
	)
	(via
		(at 457.221082 -215.166702)
		(size 0.4572)
		(drill 0.2032)
		(layers "F.Cu" "B.Cu")
		(net "GND")
	)
	(via
		(at 161.808414 -284.866588)
		(size 0.4572)
		(drill 0.2032)
		(layers "F.Cu" "B.Cu")
		(net "GND")
	)
	(via
		(at 212.724746 -216.016586)
		(size 0.4572)
		(drill 0.2032)
		(layers "F.Cu" "B.Cu")
		(net "GND")
	)
	(via
		(at 287.360614 -251.716794)
		(size 0.4572)
		(drill 0.2032)
		(layers "F.Cu" "B.Cu")
		(net "GND")
	)
	(via
		(at 59.842146 -296.766742)
		(size 0.4572)
		(drill 0.2032)
		(layers "F.Cu" "B.Cu")
		(net "GND")
	)
	(via
		(at 58.23077 -400.224244)
		(size 0.4572)
		(drill 0.254)
		(layers "F.Cu" "B.Cu")
		(net "GND")
	)
	(via
		(at 137.456418 -339.60435)
		(size 0.6604)
		(drill 0.3302)
		(layers "F.Cu" "B.Cu")
		(net "GND")
	)
	(via
		(at 450.911214 -267.016738)
		(size 0.4572)
		(drill 0.2032)
		(layers "F.Cu" "B.Cu")
		(net "GND")
	)
	(via
		(at 295.049702 -423.954448)
		(size 0.508)
		(drill 0.254)
		(layers "F.Cu" "B.Cu")
		(net "GND")
	)
	(via
		(at 309.908956 -401.492212)
		(size 0.4572)
		(drill 0.254)
		(layers "F.Cu" "B.Cu")
		(net "GND")
	)
	(via
		(at 321.250056 -432.451256)
		(size 0.4572)
		(drill 0.2032)
		(layers "F.Cu" "B.Cu")
		(net "GND")
	)
	(via
		(at 99.865434 -329.10272)
		(size 0.508)
		(drill 0.254)
		(layers "F.Cu" "B.Cu")
		(net "GND")
	)
	(via
		(at 89.554812 -234.970066)
		(size 0.4572)
		(drill 0.2032)
		(layers "F.Cu" "B.Cu")
		(net "GND")
	)
	(via
		(at 237.96752 -388.01294)
		(size 0.508)
		(drill 0.254)
		(layers "F.Cu" "B.Cu")
		(net "GND")
	)
	(via
		(at 130.076194 -257.98907)
		(size 0.4572)
		(drill 0.2032)
		(layers "F.Cu" "B.Cu")
		(net "GND")
	)
	(via
		(at 187.883546 -246.616728)
		(size 0.4572)
		(drill 0.2032)
		(layers "F.Cu" "B.Cu")
		(net "GND")
	)
	(via
		(at 28.433014 -228.766624)
		(size 0.4572)
		(drill 0.2032)
		(layers "F.Cu" "B.Cu")
		(net "GND")
	)
	(via
		(at 354.411534 -213.732618)
		(size 0.4572)
		(drill 0.2032)
		(layers "F.Cu" "B.Cu")
		(net "GND")
	)
	(via
		(at 464.764882 -239.81664)
		(size 0.4572)
		(drill 0.2032)
		(layers "F.Cu" "B.Cu")
		(net "GND")
	)
	(via
		(at 453.121014 -234.716574)
		(size 0.4572)
		(drill 0.2032)
		(layers "F.Cu" "B.Cu")
		(net "GND")
	)
	(via
		(at 119.738394 -267.755878)
		(size 0.4572)
		(drill 0.2032)
		(layers "F.Cu" "B.Cu")
		(net "GND")
	)
	(via
		(at 157.708346 -212.616796)
		(size 0.4572)
		(drill 0.2032)
		(layers "F.Cu" "B.Cu")
		(net "GND")
	)
	(via
		(at 304.338482 -228.766624)
		(size 0.4572)
		(drill 0.2032)
		(layers "F.Cu" "B.Cu")
		(net "GND")
	)
	(via
		(at 173.99381 -365.37265)
		(size 0.508)
		(drill 0.254)
		(layers "F.Cu" "B.Cu")
		(net "GND")
	)
	(via
		(at 414.070292 -170.853354)
		(size 0.49022)
		(drill 0.254)
		(layers "F.Cu" "B.Cu")
		(net "GND")
	)
	(via
		(at 134.305548 -283.219906)
		(size 0.4572)
		(drill 0.2032)
		(layers "F.Cu" "B.Cu")
		(net "GND")
	)
	(via
		(at 111.170212 -233.34218)
		(size 0.4572)
		(drill 0.2032)
		(layers "F.Cu" "B.Cu")
		(net "GND")
	)
	(via
		(at 46.964346 -217.716608)
		(size 0.4572)
		(drill 0.2032)
		(layers "F.Cu" "B.Cu")
		(net "GND")
	)
	(via
		(at 418.349938 -360.152442)
		(size 0.49022)
		(drill 0.254)
		(layers "F.Cu" "B.Cu")
		(net "GND")
	)
	(via
		(at 180.339746 -199.01662)
		(size 0.4572)
		(drill 0.2032)
		(layers "F.Cu" "B.Cu")
		(net "GND")
	)
	(via
		(at 149.05228 -79.924148)
		(size 0.508)
		(drill 0.254)
		(layers "F.Cu" "B.Cu")
		(net "GND")
	)
	(via
		(at 116.918994 -277.522432)
		(size 0.4572)
		(drill 0.2032)
		(layers "F.Cu" "B.Cu")
		(net "GND")
	)
	(via
		(at 383.545334 -221.94774)
		(size 0.4572)
		(drill 0.2032)
		(layers "F.Cu" "B.Cu")
		(net "GND")
	)
	(via
		(at 29.666946 -289.11677)
		(size 0.4572)
		(drill 0.2032)
		(layers "F.Cu" "B.Cu")
		(net "GND")
	)
	(via
		(at 316.380622 -61.331348)
		(size 0.508)
		(drill 0.254)
		(layers "F.Cu" "B.Cu")
		(net "GND")
	)
	(via
		(at 418.030152 -323.429376)
		(size 0.4572)
		(drill 0.2032)
		(layers "F.Cu" "B.Cu")
		(net "GND")
	)
	(via
		(at 436.924196 -384.54203)
		(size 0.508)
		(drill 0.254)
		(layers "F.Cu" "B.Cu")
		(net "GND")
	)
	(via
		(at 210.514946 -317.166752)
		(size 0.4572)
		(drill 0.2032)
		(layers "F.Cu" "B.Cu")
		(net "GND")
	)
	(via
		(at 384.124962 -281.59202)
		(size 0.4572)
		(drill 0.2032)
		(layers "F.Cu" "B.Cu")
		(net "GND")
	)
	(via
		(at 201.737214 -295.916604)
		(size 0.4572)
		(drill 0.2032)
		(layers "F.Cu" "B.Cu")
		(net "GND")
	)
	(via
		(at 93.894148 -270.19758)
		(size 0.4572)
		(drill 0.2032)
		(layers "F.Cu" "B.Cu")
		(net "GND")
	)
	(via
		(at 427.764448 -19.759422)
		(size 0.508)
		(drill 0.254)
		(layers "F.Cu" "B.Cu")
		(net "GND")
	)
	(via
		(at 411.349952 -429.147224)
		(size 0.4572)
		(drill 0.2032)
		(layers "F.Cu" "B.Cu")
		(net "GND")
	)
	(via
		(at 272.273014 -233.016806)
		(size 0.4572)
		(drill 0.2032)
		(layers "F.Cu" "B.Cu")
		(net "GND")
	)
	(via
		(at 409.69692 -165.123368)
		(size 0.508)
		(drill 0.254)
		(layers "F.Cu" "B.Cu")
		(net "GND")
	)
	(via
		(at 374.257062 -259.616956)
		(size 0.4572)
		(drill 0.2032)
		(layers "F.Cu" "B.Cu")
		(net "GND")
	)
	(via
		(at 381.195834 -242.294918)
		(size 0.4572)
		(drill 0.2032)
		(layers "F.Cu" "B.Cu")
		(net "GND")
	)
	(via
		(at 364.88878 -390.390888)
		(size 0.508)
		(drill 0.254)
		(layers "F.Cu" "B.Cu")
		(net "GND")
	)
	(via
		(at 54.508146 -281.466798)
		(size 0.4572)
		(drill 0.2032)
		(layers "F.Cu" "B.Cu")
		(net "GND")
	)
	(via
		(at 427.045882 -235.566712)
		(size 0.4572)
		(drill 0.2032)
		(layers "F.Cu" "B.Cu")
		(net "GND")
	)
	(via
		(at 180.339746 -296.766742)
		(size 0.4572)
		(drill 0.2032)
		(layers "F.Cu" "B.Cu")
		(net "GND")
	)
	(via
		(at 11.135614 -294.216582)
		(size 0.4572)
		(drill 0.2032)
		(layers "F.Cu" "B.Cu")
		(net "GND")
	)
	(via
		(at 466.5345 -94.902528)
		(size 0.508)
		(drill 0.254)
		(layers "F.Cu" "B.Cu")
		(net "GND")
	)
	(via
		(at 210.514946 -278.066754)
		(size 0.4572)
		(drill 0.2032)
		(layers "F.Cu" "B.Cu")
		(net "GND")
	)
	(via
		(at 423.9387 -6.586474)
		(size 0.508)
		(drill 0.254)
		(layers "F.Cu" "B.Cu")
		(net "GND")
	)
	(via
		(at 345.15171 -52.59324)
		(size 0.4572)
		(drill 0.2032)
		(layers "F.Cu" "B.Cu")
		(net "GND")
	)
	(via
		(at 22.123146 -279.766776)
		(size 0.4572)
		(drill 0.2032)
		(layers "F.Cu" "B.Cu")
		(net "GND")
	)
	(via
		(at 187.883546 -199.01662)
		(size 0.4572)
		(drill 0.2032)
		(layers "F.Cu" "B.Cu")
		(net "GND")
	)
	(via
		(at 355.28758 -332.570074)
		(size 0.49022)
		(drill 0.254)
		(layers "F.Cu" "B.Cu")
		(net "GND")
	)
	(via
		(at 281.707082 -258.516628)
		(size 0.4572)
		(drill 0.2032)
		(layers "F.Cu" "B.Cu")
		(net "GND")
	)
	(via
		(at 54.508146 -233.016806)
		(size 0.4572)
		(drill 0.2032)
		(layers "F.Cu" "B.Cu")
		(net "GND")
	)
	(via
		(at 136.654794 -280.778204)
		(size 0.4572)
		(drill 0.2032)
		(layers "F.Cu" "B.Cu")
		(net "GND")
	)
	(via
		(at 366.159034 -219.506038)
		(size 0.4572)
		(drill 0.2032)
		(layers "F.Cu" "B.Cu")
		(net "GND")
	)
	(via
		(at 29.186886 -163.303204)
		(size 0.508)
		(drill 0.254)
		(layers "F.Cu" "B.Cu")
		(net "GND")
	)
	(via
		(at 338.250022 -439.651394)
		(size 0.4572)
		(drill 0.2032)
		(layers "F.Cu" "B.Cu")
		(net "GND")
	)
	(via
		(at 413.50438 -167.071548)
		(size 0.508)
		(drill 0.254)
		(layers "F.Cu" "B.Cu")
		(net "GND")
	)
	(via
		(at 350.705674 -178.868832)
		(size 0.508)
		(drill 0.254)
		(layers "F.Cu" "B.Cu")
		(net "GND")
	)
	(via
		(at 120.97639 -251.441204)
		(size 0.4572)
		(drill 0.2032)
		(layers "F.Cu" "B.Cu")
		(net "GND")
	)
	(via
		(at 51.064414 -291.666676)
		(size 0.4572)
		(drill 0.2032)
		(layers "F.Cu" "B.Cu")
		(net "GND")
	)
	(via
		(at 309.992014 -233.016806)
		(size 0.4572)
		(drill 0.2032)
		(layers "F.Cu" "B.Cu")
		(net "GND")
	)
	(via
		(at 176.896014 -238.116618)
		(size 0.4572)
		(drill 0.2032)
		(layers "F.Cu" "B.Cu")
		(net "GND")
	)
	(via
		(at 30.440884 -323.434456)
		(size 0.4572)
		(drill 0.2032)
		(layers "F.Cu" "B.Cu")
		(net "GND")
	)
	(via
		(at 191.983614 -250.866656)
		(size 0.4572)
		(drill 0.2032)
		(layers "F.Cu" "B.Cu")
		(net "GND")
	)
	(via
		(at 368.03838 -221.133924)
		(size 0.4572)
		(drill 0.2032)
		(layers "F.Cu" "B.Cu")
		(net "GND")
	)
	(via
		(at 15.336266 -18.246344)
		(size 0.508)
		(drill 0.254)
		(layers "F.Cu" "B.Cu")
		(net "GND")
	)
	(via
		(at 358.42321 -360.753406)
		(size 0.508)
		(drill 0.254)
		(layers "F.Cu" "B.Cu")
		(net "GND")
	)
	(via
		(at 31.876746 -238.966756)
		(size 0.4572)
		(drill 0.2032)
		(layers "F.Cu" "B.Cu")
		(net "GND")
	)
	(via
		(at 426.595032 -392.155934)
		(size 0.508)
		(drill 0.254)
		(layers "F.Cu" "B.Cu")
		(net "GND")
	)
	(via
		(at 7.035546 -265.316716)
		(size 0.4572)
		(drill 0.2032)
		(layers "F.Cu" "B.Cu")
		(net "GND")
	)
	(via
		(at 402.331174 -4.317746)
		(size 0.508)
		(drill 0.254)
		(layers "F.Cu" "B.Cu")
		(net "GND")
	)
	(via
		(at 380.835662 -266.128246)
		(size 0.4572)
		(drill 0.2032)
		(layers "F.Cu" "B.Cu")
		(net "GND")
	)
	(via
		(at 163.63823 -120.106948)
		(size 0.508)
		(drill 0.254)
		(layers "F.Cu" "B.Cu")
		(net "GND")
	)
	(via
		(at 23.060152 -412.450534)
		(size 0.508)
		(drill 0.254)
		(layers "F.Cu" "B.Cu")
		(net "GND")
	)
	(via
		(at 382.245616 -255.547622)
		(size 0.4572)
		(drill 0.2032)
		(layers "F.Cu" "B.Cu")
		(net "GND")
	)
	(via
		(at 171.562014 -232.166668)
		(size 0.4572)
		(drill 0.2032)
		(layers "F.Cu" "B.Cu")
		(net "GND")
	)
	(via
		(at 405.513794 -285.742126)
		(size 0.4572)
		(drill 0.2032)
		(layers "F.Cu" "B.Cu")
		(net "GND")
	)
	(via
		(at 335.399888 -410.030168)
		(size 0.4064)
		(drill 0.2032)
		(layers "F.Cu" "B.Cu")
		(net "GND")
	)
	(via
		(at 381.195834 -216.25052)
		(size 0.4572)
		(drill 0.2032)
		(layers "F.Cu" "B.Cu")
		(net "GND")
	)
	(via
		(at 135.135366 -237.411514)
		(size 0.4572)
		(drill 0.2032)
		(layers "F.Cu" "B.Cu")
		(net "GND")
	)
	(via
		(at 323.991478 -68.447158)
		(size 0.508)
		(drill 0.254)
		(layers "F.Cu" "B.Cu")
		(net "GND")
	)
	(via
		(at 336.08518 -335.187036)
		(size 0.49022)
		(drill 0.254)
		(layers "F.Cu" "B.Cu")
		(net "GND")
	)
	(via
		(at 108.686346 -330.42352)
		(size 0.508)
		(drill 0.254)
		(layers "F.Cu" "B.Cu")
		(net "GND")
	)
	(via
		(at 303.149 -47.996348)
		(size 0.508)
		(drill 0.254)
		(layers "F.Cu" "B.Cu")
		(net "GND")
	)
	(via
		(at 352.641662 -277.522432)
		(size 0.4572)
		(drill 0.2032)
		(layers "F.Cu" "B.Cu")
		(net "GND")
	)
	(via
		(at 405.648414 -199.01662)
		(size 0.4572)
		(drill 0.2032)
		(layers "F.Cu" "B.Cu")
		(net "GND")
	)
	(via
		(at 193.991738 -194.14109)
		(size 0.508)
		(drill 0.254)
		(layers "F.Cu" "B.Cu")
		(net "GND")
	)
	(via
		(at 337.134962 -284.847538)
		(size 0.4572)
		(drill 0.2032)
		(layers "F.Cu" "B.Cu")
		(net "GND")
	)
	(via
		(at 285.150814 -221.96679)
		(size 0.4572)
		(drill 0.2032)
		(layers "F.Cu" "B.Cu")
		(net "GND")
	)
	(via
		(at 415.307018 -149.972776)
		(size 0.508)
		(drill 0.254)
		(layers "F.Cu" "B.Cu")
		(net "GND")
	)
	(via
		(at 274.163282 -303.566576)
		(size 0.4572)
		(drill 0.2032)
		(layers "F.Cu" "B.Cu")
		(net "GND")
	)
	(via
		(at 350.867726 -255.817624)
		(size 0.4572)
		(drill 0.2032)
		(layers "F.Cu" "B.Cu")
		(net "GND")
	)
	(via
		(at 13.345414 -291.666676)
		(size 0.4572)
		(drill 0.2032)
		(layers "F.Cu" "B.Cu")
		(net "GND")
	)
	(via
		(at 394.84681 -9.424924)
		(size 0.508)
		(drill 0.254)
		(layers "F.Cu" "B.Cu")
		(net "GND")
	)
	(via
		(at 199.527414 -224.516696)
		(size 0.4572)
		(drill 0.2032)
		(layers "F.Cu" "B.Cu")
		(net "GND")
	)
	(via
		(at 58.608214 -205.816708)
		(size 0.4572)
		(drill 0.2032)
		(layers "F.Cu" "B.Cu")
		(net "GND")
	)
	(via
		(at 120.098312 -221.133924)
		(size 0.4572)
		(drill 0.2032)
		(layers "F.Cu" "B.Cu")
		(net "GND")
	)
	(via
		(at 163.827714 -407.00452)
		(size 0.4064)
		(drill 0.2032)
		(layers "F.Cu" "B.Cu")
		(net "GND")
	)
	(via
		(at 220.452188 -95.6183)
		(size 0.508)
		(drill 0.254)
		(layers "F.Cu" "B.Cu")
		(net "GND")
	)
	(via
		(at 147.526502 -403.249892)
		(size 0.4572)
		(drill 0.254)
		(layers "F.Cu" "B.Cu")
		(net "GND")
	)
	(via
		(at 416.300158 -5.585714)
		(size 0.508)
		(drill 0.254)
		(layers "F.Cu" "B.Cu")
		(net "GND")
	)
	(via
		(at 460.664814 -229.616762)
		(size 0.4572)
		(drill 0.2032)
		(layers "F.Cu" "B.Cu")
		(net "GND")
	)
	(via
		(at 289.250882 -228.766624)
		(size 0.4572)
		(drill 0.2032)
		(layers "F.Cu" "B.Cu")
		(net "GND")
	)
	(via
		(at 368.148362 -288.103056)
		(size 0.4572)
		(drill 0.2032)
		(layers "F.Cu" "B.Cu")
		(net "GND")
	)
	(via
		(at 197.637146 -306.116736)
		(size 0.4572)
		(drill 0.2032)
		(layers "F.Cu" "B.Cu")
		(net "GND")
	)
	(via
		(at 56.398414 -205.816708)
		(size 0.4572)
		(drill 0.2032)
		(layers "F.Cu" "B.Cu")
		(net "GND")
	)
	(via
		(at 108.68152 -128.636268)
		(size 0.508)
		(drill 0.254)
		(layers "F.Cu" "B.Cu")
		(net "GND")
	)
	(via
		(at 420.883588 -18.491454)
		(size 0.508)
		(drill 0.254)
		(layers "F.Cu" "B.Cu")
		(net "GND")
	)
	(via
		(at 11.135614 -275.516594)
		(size 0.4572)
		(drill 0.2032)
		(layers "F.Cu" "B.Cu")
		(net "GND")
	)
	(via
		(at 361.460034 -230.900478)
		(size 0.4572)
		(drill 0.2032)
		(layers "F.Cu" "B.Cu")
		(net "GND")
	)
	(via
		(at 139.682982 -410.664152)
		(size 0.4572)
		(drill 0.254)
		(layers "F.Cu" "B.Cu")
		(net "GND")
	)
	(via
		(at 46.964346 -248.31675)
		(size 0.4572)
		(drill 0.2032)
		(layers "F.Cu" "B.Cu")
		(net "GND")
	)
	(via
		(at 175.005746 -199.01662)
		(size 0.4572)
		(drill 0.2032)
		(layers "F.Cu" "B.Cu")
		(net "GND")
	)
	(via
		(at 65.25006 -434.899562)
		(size 0.4572)
		(drill 0.2032)
		(layers "F.Cu" "B.Cu")
		(net "GND")
	)
	(via
		(at 455.011282 -224.516696)
		(size 0.4572)
		(drill 0.2032)
		(layers "F.Cu" "B.Cu")
		(net "GND")
	)
	(via
		(at 460.664814 -298.466764)
		(size 0.4572)
		(drill 0.2032)
		(layers "F.Cu" "B.Cu")
		(net "GND")
	)
	(via
		(at 246.393716 -123.370086)
		(size 0.508)
		(drill 0.254)
		(layers "F.Cu" "B.Cu")
		(net "GND")
	)
	(via
		(at 407.984198 -401.492212)
		(size 0.4572)
		(drill 0.254)
		(layers "F.Cu" "B.Cu")
		(net "GND")
	)
	(via
		(at 161.808414 -314.616592)
		(size 0.4572)
		(drill 0.2032)
		(layers "F.Cu" "B.Cu")
		(net "GND")
	)
	(via
		(at 450.911214 -204.96657)
		(size 0.4572)
		(drill 0.2032)
		(layers "F.Cu" "B.Cu")
		(net "GND")
	)
	(via
		(at 42.940732 -0.76454)
		(size 0.508)
		(drill 0.254)
		(layers "F.Cu" "B.Cu")
		(net "GND")
	)
	(via
		(at 161.808414 -207.51673)
		(size 0.4572)
		(drill 0.2032)
		(layers "F.Cu" "B.Cu")
		(net "GND")
	)
	(via
		(at 420.736014 -265.316716)
		(size 0.4572)
		(drill 0.2032)
		(layers "F.Cu" "B.Cu")
		(net "GND")
	)
	(via
		(at 32.682688 -5.596636)
		(size 0.508)
		(drill 0.254)
		(layers "F.Cu" "B.Cu")
		(net "GND")
	)
	(via
		(at 100.362766 -219.506038)
		(size 0.4572)
		(drill 0.2032)
		(layers "F.Cu" "B.Cu")
		(net "GND")
	)
	(via
		(at 125.847094 -271.825212)
		(size 0.4572)
		(drill 0.2032)
		(layers "F.Cu" "B.Cu")
		(net "GND")
	)
	(via
		(at 136.349994 -433.747164)
		(size 0.4572)
		(drill 0.2032)
		(layers "F.Cu" "B.Cu")
		(net "GND")
	)
	(via
		(at 205.180946 -248.31675)
		(size 0.4572)
		(drill 0.2032)
		(layers "F.Cu" "B.Cu")
		(net "GND")
	)
	(via
		(at 405.496776 -54.743604)
		(size 0.508)
		(drill 0.254)
		(layers "F.Cu" "B.Cu")
		(net "GND")
	)
	(via
		(at 167.461946 -281.466798)
		(size 0.4572)
		(drill 0.2032)
		(layers "F.Cu" "B.Cu")
		(net "GND")
	)
	(via
		(at 459.1939 -388.06882)
		(size 0.508)
		(drill 0.254)
		(layers "F.Cu" "B.Cu")
		(net "GND")
	)
	(via
		(at 374.147334 -228.45903)
		(size 0.4572)
		(drill 0.2032)
		(layers "F.Cu" "B.Cu")
		(net "GND")
	)
	(via
		(at 79.324454 -340.977728)
		(size 0.49022)
		(drill 0.254)
		(layers "F.Cu" "B.Cu")
		(net "GND")
	)
	(via
		(at 19.769582 -429.047148)
		(size 0.508)
		(drill 0.254)
		(layers "F.Cu" "B.Cu")
		(net "GND")
	)
	(via
		(at 404.1267 -6.07949)
		(size 0.508)
		(drill 0.254)
		(layers "F.Cu" "B.Cu")
		(net "GND")
	)
	(via
		(at 217.601292 -150.878794)
		(size 0.508)
		(drill 0.254)
		(layers "F.Cu" "B.Cu")
		(net "GND")
	)
	(via
		(at 71.926958 -400.858228)
		(size 0.4064)
		(drill 0.2032)
		(layers "F.Cu" "B.Cu")
		(net "GND")
	)
	(via
		(at 158.812484 -323.383656)
		(size 0.4572)
		(drill 0.2032)
		(layers "F.Cu" "B.Cu")
		(net "GND")
	)
	(via
		(at 108.686346 -329.76312)
		(size 0.508)
		(drill 0.254)
		(layers "F.Cu" "B.Cu")
		(net "GND")
	)
	(via
		(at 346.532962 -255.547622)
		(size 0.4572)
		(drill 0.2032)
		(layers "F.Cu" "B.Cu")
		(net "GND")
	)
	(via
		(at 420.567866 -359.414572)
		(size 0.508)
		(drill 0.254)
		(layers "F.Cu" "B.Cu")
		(net "GND")
	)
	(via
		(at 383.075434 -227.64496)
		(size 0.4572)
		(drill 0.2032)
		(layers "F.Cu" "B.Cu")
		(net "GND")
	)
	(via
		(at 159.918146 -265.316716)
		(size 0.4572)
		(drill 0.2032)
		(layers "F.Cu" "B.Cu")
		(net "GND")
	)
	(via
		(at 94.32798 -94.899988)
		(size 0.508)
		(drill 0.254)
		(layers "F.Cu" "B.Cu")
		(net "GND")
	)
	(via
		(at 31.876746 -300.166786)
		(size 0.4572)
		(drill 0.2032)
		(layers "F.Cu" "B.Cu")
		(net "GND")
	)
	(via
		(at 381.195834 -227.64496)
		(size 0.4572)
		(drill 0.2032)
		(layers "F.Cu" "B.Cu")
		(net "GND")
	)
	(via
		(at 59.842146 -248.31675)
		(size 0.4572)
		(drill 0.2032)
		(layers "F.Cu" "B.Cu")
		(net "GND")
	)
	(via
		(at 23.93188 -428.401988)
		(size 0.508)
		(drill 0.254)
		(layers "F.Cu" "B.Cu")
		(net "GND")
	)
	(via
		(at 314.092082 -278.916638)
		(size 0.4572)
		(drill 0.2032)
		(layers "F.Cu" "B.Cu")
		(net "GND")
	)
	(via
		(at 78.414626 -404.51786)
		(size 0.4572)
		(drill 0.254)
		(layers "F.Cu" "B.Cu")
		(net "GND")
	)
	(via
		(at 300.99762 -414.78454)
		(size 0.508)
		(drill 0.254)
		(layers "F.Cu" "B.Cu")
		(net "GND")
	)
	(via
		(at 405.072596 -19.759422)
		(size 0.508)
		(drill 0.254)
		(layers "F.Cu" "B.Cu")
		(net "GND")
	)
	(via
		(at 222.484188 -96.467422)
		(size 0.508)
		(drill 0.254)
		(layers "F.Cu" "B.Cu")
		(net "GND")
	)
	(via
		(at 257.185414 -309.51678)
		(size 0.4572)
		(drill 0.2032)
		(layers "F.Cu" "B.Cu")
		(net "GND")
	)
	(via
		(at 453.121014 -246.616728)
		(size 0.4572)
		(drill 0.2032)
		(layers "F.Cu" "B.Cu")
		(net "GND")
	)
	(via
		(at 283.916882 -282.316682)
		(size 0.4572)
		(drill 0.2032)
		(layers "F.Cu" "B.Cu")
		(net "GND")
	)
	(via
		(at 71.250048 -433.899564)
		(size 0.4572)
		(drill 0.2032)
		(layers "F.Cu" "B.Cu")
		(net "GND")
	)
	(via
		(at 385.048252 -341.766906)
		(size 0.49022)
		(drill 0.254)
		(layers "F.Cu" "B.Cu")
		(net "GND")
	)
	(via
		(at 292.694614 -281.466798)
		(size 0.4572)
		(drill 0.2032)
		(layers "F.Cu" "B.Cu")
		(net "GND")
	)
	(via
		(at 14.426946 -388.135876)
		(size 0.508)
		(drill 0.254)
		(layers "F.Cu" "B.Cu")
		(net "GND")
	)
	(via
		(at 262.180832 -439.905394)
		(size 0.508)
		(drill 0.254)
		(layers "F.Cu" "B.Cu")
		(net "GND")
	)
	(via
		(at 279.816814 -292.516814)
		(size 0.4572)
		(drill 0.2032)
		(layers "F.Cu" "B.Cu")
		(net "GND")
	)
	(via
		(at 108.351066 -220.319854)
		(size 0.4572)
		(drill 0.2032)
		(layers "F.Cu" "B.Cu")
		(net "GND")
	)
	(via
		(at 175.005746 -206.666592)
		(size 0.4572)
		(drill 0.2032)
		(layers "F.Cu" "B.Cu")
		(net "GND")
	)
	(via
		(at 346.423234 -242.294918)
		(size 0.4572)
		(drill 0.2032)
		(layers "F.Cu" "B.Cu")
		(net "GND")
	)
	(via
		(at 419.904672 -360.074972)
		(size 0.508)
		(drill 0.254)
		(layers "F.Cu" "B.Cu")
		(net "GND")
	)
	(via
		(at 387.887718 -410.664152)
		(size 0.4572)
		(drill 0.254)
		(layers "F.Cu" "B.Cu")
		(net "GND")
	)
	(via
		(at 262.519414 -265.316716)
		(size 0.4572)
		(drill 0.2032)
		(layers "F.Cu" "B.Cu")
		(net "GND")
	)
	(via
		(at 48.854614 -200.716642)
		(size 0.4572)
		(drill 0.2032)
		(layers "F.Cu" "B.Cu")
		(net "GND")
	)
	(via
		(at 107.051348 -278.336502)
		(size 0.4572)
		(drill 0.2032)
		(layers "F.Cu" "B.Cu")
		(net "GND")
	)
	(via
		(at 338.966556 -335.1911)
		(size 0.49022)
		(drill 0.254)
		(layers "F.Cu" "B.Cu")
		(net "GND")
	)
	(via
		(at 349.556832 -332.363826)
		(size 0.508)
		(drill 0.254)
		(layers "F.Cu" "B.Cu")
		(net "GND")
	)
	(via
		(at 101.882194 -287.28924)
		(size 0.4572)
		(drill 0.2032)
		(layers "F.Cu" "B.Cu")
		(net "GND")
	)
	(via
		(at 439.923682 -200.716642)
		(size 0.4572)
		(drill 0.2032)
		(layers "F.Cu" "B.Cu")
		(net "GND")
	)
	(via
		(at 165.252146 -242.3668)
		(size 0.4572)
		(drill 0.2032)
		(layers "F.Cu" "B.Cu")
		(net "GND")
	)
	(via
		(at 129.496566 -245.55069)
		(size 0.4572)
		(drill 0.2032)
		(layers "F.Cu" "B.Cu")
		(net "GND")
	)
	(via
		(at 210.514946 -265.316716)
		(size 0.4572)
		(drill 0.2032)
		(layers "F.Cu" "B.Cu")
		(net "GND")
	)
	(via
		(at 361.227116 -332.56601)
		(size 0.49022)
		(drill 0.254)
		(layers "F.Cu" "B.Cu")
		(net "GND")
	)
	(via
		(at 199.42429 -68.026788)
		(size 0.508)
		(drill 0.254)
		(layers "F.Cu" "B.Cu")
		(net "GND")
	)
	(via
		(at 56.182514 -272.966688)
		(size 0.4572)
		(drill 0.2032)
		(layers "F.Cu" "B.Cu")
		(net "GND")
	)
	(via
		(at 34.894266 -19.770344)
		(size 0.508)
		(drill 0.254)
		(layers "F.Cu" "B.Cu")
		(net "GND")
	)
	(via
		(at 306.548282 -224.516696)
		(size 0.4572)
		(drill 0.2032)
		(layers "F.Cu" "B.Cu")
		(net "GND")
	)
	(via
		(at 398.446752 -12.37488)
		(size 0.508)
		(drill 0.254)
		(layers "F.Cu" "B.Cu")
		(net "GND")
	)
	(via
		(at 274.163282 -280.61666)
		(size 0.4572)
		(drill 0.2032)
		(layers "F.Cu" "B.Cu")
		(net "GND")
	)
	(via
		(at 9.245346 -214.316564)
		(size 0.4572)
		(drill 0.2032)
		(layers "F.Cu" "B.Cu")
		(net "GND")
	)
	(via
		(at 352.960686 -36.903914)
		(size 0.508)
		(drill 0.254)
		(layers "F.Cu" "B.Cu")
		(net "GND")
	)
	(via
		(at 90.134694 -255.547622)
		(size 0.4572)
		(drill 0.2032)
		(layers "F.Cu" "B.Cu")
		(net "GND")
	)
	(via
		(at 443.367414 -306.116736)
		(size 0.4572)
		(drill 0.2032)
		(layers "F.Cu" "B.Cu")
		(net "GND")
	)
	(via
		(at 9.245346 -311.216802)
		(size 0.4572)
		(drill 0.2032)
		(layers "F.Cu" "B.Cu")
		(net "GND")
	)
	(via
		(at 304.338482 -258.516628)
		(size 0.4572)
		(drill 0.2032)
		(layers "F.Cu" "B.Cu")
		(net "GND")
	)
	(via
		(at 54.3814 -173.069504)
		(size 0.508)
		(drill 0.254)
		(layers "F.Cu" "B.Cu")
		(net "GND")
	)
	(via
		(at 13.345414 -294.216582)
		(size 0.4572)
		(drill 0.2032)
		(layers "F.Cu" "B.Cu")
		(net "GND")
	)
	(via
		(at 136.654794 -267.755878)
		(size 0.4572)
		(drill 0.2032)
		(layers "F.Cu" "B.Cu")
		(net "GND")
	)
	(via
		(at 82.250026 -437.34736)
		(size 0.4572)
		(drill 0.2032)
		(layers "F.Cu" "B.Cu")
		(net "GND")
	)
	(via
		(at 33.767014 -314.616592)
		(size 0.4572)
		(drill 0.2032)
		(layers "F.Cu" "B.Cu")
		(net "GND")
	)
	(via
		(at 425.573952 -323.429376)
		(size 0.4572)
		(drill 0.2032)
		(layers "F.Cu" "B.Cu")
		(net "GND")
	)
	(via
		(at 424.653964 -441.225432)
		(size 0.508)
		(drill 0.254)
		(layers "F.Cu" "B.Cu")
		(net "GND")
	)
	(via
		(at 165.252146 -197.316598)
		(size 0.4572)
		(drill 0.2032)
		(layers "F.Cu" "B.Cu")
		(net "GND")
	)
	(via
		(at 156.090874 -50.896012)
		(size 0.508)
		(drill 0.254)
		(layers "F.Cu" "B.Cu")
		(net "GND")
	)
	(via
		(at 394.84681 -7.215124)
		(size 0.508)
		(drill 0.254)
		(layers "F.Cu" "B.Cu")
		(net "GND")
	)
	(via
		(at 335.255362 -266.941808)
		(size 0.4318)
		(drill 0.2032)
		(layers "F.Cu" "B.Cu")
		(net "GND")
	)
	(via
		(at 314.092082 -289.966654)
		(size 0.4572)
		(drill 0.2032)
		(layers "F.Cu" "B.Cu")
		(net "GND")
	)
	(via
		(at 199.527414 -238.116618)
		(size 0.4572)
		(drill 0.2032)
		(layers "F.Cu" "B.Cu")
		(net "GND")
	)
	(via
		(at 262.519414 -263.616694)
		(size 0.4572)
		(drill 0.2032)
		(layers "F.Cu" "B.Cu")
		(net "GND")
	)
	(via
		(at 187.883546 -273.816572)
		(size 0.4572)
		(drill 0.2032)
		(layers "F.Cu" "B.Cu")
		(net "GND")
	)
	(via
		(at 51.064414 -258.516628)
		(size 0.4572)
		(drill 0.2032)
		(layers "F.Cu" "B.Cu")
		(net "GND")
	)
	(via
		(at 129.606294 -263.686544)
		(size 0.4572)
		(drill 0.2032)
		(layers "F.Cu" "B.Cu")
		(net "GND")
	)
	(via
		(at 209.281014 -297.616626)
		(size 0.4572)
		(drill 0.2032)
		(layers "F.Cu" "B.Cu")
		(net "GND")
	)
	(via
		(at 43.520614 -211.766658)
		(size 0.4572)
		(drill 0.2032)
		(layers "F.Cu" "B.Cu")
		(net "GND")
	)
	(via
		(at 175.208946 -311.216802)
		(size 0.4572)
		(drill 0.2032)
		(layers "F.Cu" "B.Cu")
		(net "GND")
	)
	(via
		(at 29.082492 -4.328668)
		(size 0.508)
		(drill 0.254)
		(layers "F.Cu" "B.Cu")
		(net "GND")
	)
	(via
		(at 182.549546 -289.11677)
		(size 0.4572)
		(drill 0.2032)
		(layers "F.Cu" "B.Cu")
		(net "GND")
	)
	(via
		(at 272.725896 -121.124218)
		(size 0.508)
		(drill 0.254)
		(layers "F.Cu" "B.Cu")
		(net "GND")
	)
	(via
		(at 352.062034 -216.25052)
		(size 0.4572)
		(drill 0.2032)
		(layers "F.Cu" "B.Cu")
		(net "GND")
	)
	(via
		(at 323.146928 -407.00452)
		(size 0.4064)
		(drill 0.2032)
		(layers "F.Cu" "B.Cu")
		(net "GND")
	)
	(via
		(at 152.209754 -403.883876)
		(size 0.4064)
		(drill 0.2032)
		(layers "F.Cu" "B.Cu")
		(net "GND")
	)
	(via
		(at 322.161916 -403.249892)
		(size 0.4572)
		(drill 0.254)
		(layers "F.Cu" "B.Cu")
		(net "GND")
	)
	(via
		(at 291.460682 -238.116618)
		(size 0.4572)
		(drill 0.2032)
		(layers "F.Cu" "B.Cu")
		(net "GND")
	)
	(via
		(at 87.315294 -279.964134)
		(size 0.4572)
		(drill 0.2032)
		(layers "F.Cu" "B.Cu")
		(net "GND")
	)
	(via
		(at 457.221082 -277.216616)
		(size 0.4572)
		(drill 0.2032)
		(layers "F.Cu" "B.Cu")
		(net "GND")
	)
	(via
		(at 345.483434 -234.15625)
		(size 0.4572)
		(drill 0.2032)
		(layers "F.Cu" "B.Cu")
		(net "GND")
	)
	(via
		(at 175.005746 -223.666558)
		(size 0.4572)
		(drill 0.2032)
		(layers "F.Cu" "B.Cu")
		(net "GND")
	)
	(via
		(at 120.787414 -332.56601)
		(size 0.49022)
		(drill 0.254)
		(layers "F.Cu" "B.Cu")
		(net "GND")
	)
	(via
		(at 51.064414 -308.666642)
		(size 0.4572)
		(drill 0.2032)
		(layers "F.Cu" "B.Cu")
		(net "GND")
	)
	(via
		(at 150.589742 -400.224244)
		(size 0.4572)
		(drill 0.254)
		(layers "F.Cu" "B.Cu")
		(net "GND")
	)
	(via
		(at 88.250014 -436.347362)
		(size 0.4572)
		(drill 0.2032)
		(layers "F.Cu" "B.Cu")
		(net "GND")
	)
	(via
		(at 289.67811 -96.416368)
		(size 0.508)
		(drill 0.254)
		(layers "F.Cu" "B.Cu")
		(net "GND")
	)
	(via
		(at 117.859048 -279.150318)
		(size 0.4572)
		(drill 0.2032)
		(layers "F.Cu" "B.Cu")
		(net "GND")
	)
	(via
		(at 299.103288 -360.83621)
		(size 0.49022)
		(drill 0.254)
		(layers "F.Cu" "B.Cu")
		(net "GND")
	)
	(via
		(at 273.491706 -128.641094)
		(size 0.508)
		(drill 0.254)
		(layers "F.Cu" "B.Cu")
		(net "GND")
	)
	(via
		(at 266.619482 -277.216616)
		(size 0.4572)
		(drill 0.2032)
		(layers "F.Cu" "B.Cu")
		(net "GND")
	)
	(via
		(at 150.589742 -401.492212)
		(size 0.4572)
		(drill 0.254)
		(layers "F.Cu" "B.Cu")
		(net "GND")
	)
	(via
		(at 447.467482 -232.166668)
		(size 0.4572)
		(drill 0.2032)
		(layers "F.Cu" "B.Cu")
		(net "GND")
	)
	(via
		(at 375.557034 -247.178322)
		(size 0.4572)
		(drill 0.2032)
		(layers "F.Cu" "B.Cu")
		(net "GND")
	)
	(via
		(at 297.782488 -361.625388)
		(size 0.49022)
		(drill 0.254)
		(layers "F.Cu" "B.Cu")
		(net "GND")
	)
	(via
		(at 130.350006 -430.299622)
		(size 0.4572)
		(drill 0.2032)
		(layers "F.Cu" "B.Cu")
		(net "GND")
	)
	(via
		(at 51.064414 -202.416664)
		(size 0.4572)
		(drill 0.2032)
		(layers "F.Cu" "B.Cu")
		(net "GND")
	)
	(via
		(at 453.121014 -306.116736)
		(size 0.4572)
		(drill 0.2032)
		(layers "F.Cu" "B.Cu")
		(net "GND")
	)
	(via
		(at 119.466614 -332.56601)
		(size 0.49022)
		(drill 0.254)
		(layers "F.Cu" "B.Cu")
		(net "GND")
	)
	(via
		(at 407.359612 -48.245522)
		(size 0.508)
		(drill 0.254)
		(layers "F.Cu" "B.Cu")
		(net "GND")
	)
	(via
		(at 56.867044 -7.215124)
		(size 0.508)
		(drill 0.254)
		(layers "F.Cu" "B.Cu")
		(net "GND")
	)
	(via
		(at 120.97639 -254.946404)
		(size 0.4572)
		(drill 0.2032)
		(layers "F.Cu" "B.Cu")
		(net "GND")
	)
	(via
		(at 191.676782 -27.505152)
		(size 0.508)
		(drill 0.254)
		(layers "F.Cu" "B.Cu")
		(net "GND")
	)
	(via
		(at 175.005746 -250.016772)
		(size 0.4572)
		(drill 0.2032)
		(layers "F.Cu" "B.Cu")
		(net "GND")
	)
	(via
		(at 168.854628 -352.153728)
		(size 0.508)
		(drill 0.254)
		(layers "F.Cu" "B.Cu")
		(net "GND")
	)
	(via
		(at 413.349948 -434.899562)
		(size 0.4572)
		(drill 0.2032)
		(layers "F.Cu" "B.Cu")
		(net "GND")
	)
	(via
		(at 407.698194 -4.95173)
		(size 0.508)
		(drill 0.254)
		(layers "F.Cu" "B.Cu")
		(net "GND")
	)
	(via
		(at 458.3811 -388.06882)
		(size 0.508)
		(drill 0.254)
		(layers "F.Cu" "B.Cu")
		(net "GND")
	)
	(via
		(at 382.35001 -436.347362)
		(size 0.4572)
		(drill 0.2032)
		(layers "F.Cu" "B.Cu")
		(net "GND")
	)
	(via
		(at 445.577214 -265.316716)
		(size 0.4572)
		(drill 0.2032)
		(layers "F.Cu" "B.Cu")
		(net "GND")
	)
	(via
		(at 289.250882 -238.116618)
		(size 0.4572)
		(drill 0.2032)
		(layers "F.Cu" "B.Cu")
		(net "GND")
	)
	(via
		(at 383.655062 -287.28924)
		(size 0.4572)
		(drill 0.2032)
		(layers "F.Cu" "B.Cu")
		(net "GND")
	)
	(via
		(at 123.497594 -257.98907)
		(size 0.4572)
		(drill 0.2032)
		(layers "F.Cu" "B.Cu")
		(net "GND")
	)
	(via
		(at 167.461946 -287.213548)
		(size 0.4572)
		(drill 0.2032)
		(layers "F.Cu" "B.Cu")
		(net "GND")
	)
	(via
		(at 161.808414 -202.416664)
		(size 0.4572)
		(drill 0.2032)
		(layers "F.Cu" "B.Cu")
		(net "GND")
	)
	(via
		(at 345.15171 -42.349928)
		(size 0.4572)
		(drill 0.2032)
		(layers "F.Cu" "B.Cu")
		(net "GND")
	)
	(via
		(at 434.589682 -244.066568)
		(size 0.4572)
		(drill 0.2032)
		(layers "F.Cu" "B.Cu")
		(net "GND")
	)
	(via
		(at 276.373082 -266.1666)
		(size 0.4572)
		(drill 0.2032)
		(layers "F.Cu" "B.Cu")
		(net "GND")
	)
	(via
		(at 48.854614 -266.1666)
		(size 0.4572)
		(drill 0.2032)
		(layers "F.Cu" "B.Cu")
		(net "GND")
	)
	(via
		(at 380.05385 -403.883876)
		(size 0.4064)
		(drill 0.2032)
		(layers "F.Cu" "B.Cu")
		(net "GND")
	)
	(via
		(at 407.525982 -406.370536)
		(size 0.4572)
		(drill 0.254)
		(layers "F.Cu" "B.Cu")
		(net "GND")
	)
	(via
		(at 447.467482 -310.366664)
		(size 0.4572)
		(drill 0.2032)
		(layers "F.Cu" "B.Cu")
		(net "GND")
	)
	(via
		(at 190.093346 -301.866808)
		(size 0.4572)
		(drill 0.2032)
		(layers "F.Cu" "B.Cu")
		(net "GND")
	)
	(via
		(at 464.764882 -250.866656)
		(size 0.4572)
		(drill 0.2032)
		(layers "F.Cu" "B.Cu")
		(net "GND")
	)
	(via
		(at 372.478554 -184.655968)
		(size 0.508)
		(drill 0.254)
		(layers "F.Cu" "B.Cu")
		(net "GND")
	)
	(via
		(at 120.678194 -271.011396)
		(size 0.4572)
		(drill 0.2032)
		(layers "F.Cu" "B.Cu")
		(net "GND")
	)
	(via
		(at 424.836082 -272.966688)
		(size 0.4572)
		(drill 0.2032)
		(layers "F.Cu" "B.Cu")
		(net "GND")
	)
	(via
		(at 41.310814 -239.81664)
		(size 0.4572)
		(drill 0.2032)
		(layers "F.Cu" "B.Cu")
		(net "GND")
	)
	(via
		(at 373.291354 -181.353968)
		(size 0.508)
		(drill 0.254)
		(layers "F.Cu" "B.Cu")
		(net "GND")
	)
	(via
		(at 186.649614 -258.516628)
		(size 0.4572)
		(drill 0.2032)
		(layers "F.Cu" "B.Cu")
		(net "GND")
	)
	(via
		(at 413.454596 -18.235422)
		(size 0.508)
		(drill 0.254)
		(layers "F.Cu" "B.Cu")
		(net "GND")
	)
	(via
		(at 223.868488 -233.84637)
		(size 0.508)
		(drill 0.254)
		(layers "F.Cu" "B.Cu")
		(net "GND")
	)
	(via
		(at 384.124962 -262.058658)
		(size 0.4572)
		(drill 0.2032)
		(layers "F.Cu" "B.Cu")
		(net "GND")
	)
	(via
		(at 369.918234 -226.017328)
		(size 0.4572)
		(drill 0.2032)
		(layers "F.Cu" "B.Cu")
		(net "GND")
	)
	(via
		(at 428.279814 -311.216802)
		(size 0.4572)
		(drill 0.2032)
		(layers "F.Cu" "B.Cu")
		(net "GND")
	)
	(via
		(at 262.519414 -287.416748)
		(size 0.4572)
		(drill 0.2032)
		(layers "F.Cu" "B.Cu")
		(net "GND")
	)
	(via
		(at 421.15359 -162.435794)
		(size 0.508)
		(drill 0.254)
		(layers "F.Cu" "B.Cu")
		(net "GND")
	)
	(via
		(at 133.255766 -226.017328)
		(size 0.4572)
		(drill 0.2032)
		(layers "F.Cu" "B.Cu")
		(net "GND")
	)
	(via
		(at 161.808414 -308.666642)
		(size 0.4572)
		(drill 0.2032)
		(layers "F.Cu" "B.Cu")
		(net "GND")
	)
	(via
		(at 66.161666 -403.249892)
		(size 0.4572)
		(drill 0.254)
		(layers "F.Cu" "B.Cu")
		(net "GND")
	)
	(via
		(at 209.281014 -267.866622)
		(size 0.4572)
		(drill 0.2032)
		(layers "F.Cu" "B.Cu")
		(net "GND")
	)
	(via
		(at 300.65599 -362.422694)
		(size 0.49022)
		(drill 0.254)
		(layers "F.Cu" "B.Cu")
		(net "GND")
	)
	(via
		(at 11.135614 -316.316614)
		(size 0.4572)
		(drill 0.2032)
		(layers "F.Cu" "B.Cu")
		(net "GND")
	)
	(via
		(at 89.554812 -243.108988)
		(size 0.4572)
		(drill 0.2032)
		(layers "F.Cu" "B.Cu")
		(net "GND")
	)
	(via
		(at 434.589682 -210.066636)
		(size 0.4572)
		(drill 0.2032)
		(layers "F.Cu" "B.Cu")
		(net "GND")
	)
	(via
		(at 460.664814 -311.216802)
		(size 0.4572)
		(drill 0.2032)
		(layers "F.Cu" "B.Cu")
		(net "GND")
	)
	(via
		(at 386.18033 -403.883876)
		(size 0.4064)
		(drill 0.2032)
		(layers "F.Cu" "B.Cu")
		(net "GND")
	)
	(via
		(at 161.808414 -306.96662)
		(size 0.4572)
		(drill 0.2032)
		(layers "F.Cu" "B.Cu")
		(net "GND")
	)
	(via
		(at 31.876746 -258.516628)
		(size 0.4572)
		(drill 0.2032)
		(layers "F.Cu" "B.Cu")
		(net "GND")
	)
	(via
		(at 63.726314 -207.51673)
		(size 0.4572)
		(drill 0.2032)
		(layers "F.Cu" "B.Cu")
		(net "GND")
	)
	(via
		(at 422.497504 -130.944874)
		(size 0.508)
		(drill 0.254)
		(layers "F.Cu" "B.Cu")
		(net "GND")
	)
	(via
		(at 390.464548 -50.249836)
		(size 0.508)
		(drill 0.254)
		(layers "F.Cu" "B.Cu")
		(net "GND")
	)
	(via
		(at 172.00753 -103.698548)
		(size 0.508)
		(drill 0.254)
		(layers "F.Cu" "B.Cu")
		(net "GND")
	)
	(via
		(at 161.808414 -249.166634)
		(size 0.4572)
		(drill 0.2032)
		(layers "F.Cu" "B.Cu")
		(net "GND")
	)
	(via
		(at 123.857766 -216.25052)
		(size 0.4572)
		(drill 0.2032)
		(layers "F.Cu" "B.Cu")
		(net "GND")
	)
	(via
		(at 127.726948 -260.430772)
		(size 0.4572)
		(drill 0.2032)
		(layers "F.Cu" "B.Cu")
		(net "GND")
	)
	(via
		(at 443.557152 -332.860396)
		(size 0.4572)
		(drill 0.2032)
		(layers "F.Cu" "B.Cu")
		(net "GND")
	)
	(via
		(at 299.786548 -163.122864)
		(size 0.508)
		(drill 0.254)
		(layers "F.Cu" "B.Cu")
		(net "GND")
	)
	(via
		(at 370.858034 -235.783882)
		(size 0.4572)
		(drill 0.2032)
		(layers "F.Cu" "B.Cu")
		(net "GND")
	)
	(via
		(at 378.376434 -247.178322)
		(size 0.4572)
		(drill 0.2032)
		(layers "F.Cu" "B.Cu")
		(net "GND")
	)
	(via
		(at 66.064638 -407.00452)
		(size 0.4064)
		(drill 0.2032)
		(layers "F.Cu" "B.Cu")
		(net "GND")
	)
	(via
		(at 403.349968 -425.547282)
		(size 0.4572)
		(drill 0.2032)
		(layers "F.Cu" "B.Cu")
		(net "GND")
	)
	(via
		(at 14.579346 -313.766708)
		(size 0.4572)
		(drill 0.2032)
		(layers "F.Cu" "B.Cu")
		(net "GND")
	)
	(via
		(at 29.666946 -283.166566)
		(size 0.4572)
		(drill 0.2032)
		(layers "F.Cu" "B.Cu")
		(net "GND")
	)
	(via
		(at 287.360614 -301.866808)
		(size 0.4572)
		(drill 0.2032)
		(layers "F.Cu" "B.Cu")
		(net "GND")
	)
	(via
		(at 396.422118 -164.724588)
		(size 0.508)
		(drill 0.254)
		(layers "F.Cu" "B.Cu")
		(net "GND")
	)
	(via
		(at 417.997894 -163.692078)
		(size 0.49022)
		(drill 0.254)
		(layers "F.Cu" "B.Cu")
		(net "GND")
	)
	(via
		(at 432.379882 -267.866622)
		(size 0.4572)
		(drill 0.2032)
		(layers "F.Cu" "B.Cu")
		(net "GND")
	)
	(via
		(at 110.340394 -275.8948)
		(size 0.4572)
		(drill 0.2032)
		(layers "F.Cu" "B.Cu")
		(net "GND")
	)
	(via
		(at 299.004482 -230.466646)
		(size 0.4572)
		(drill 0.2032)
		(layers "F.Cu" "B.Cu")
		(net "GND")
	)
	(via
		(at 185.2168 -149.593808)
		(size 0.508)
		(drill 0.254)
		(layers "F.Cu" "B.Cu")
		(net "GND")
	)
	(via
		(at 107.051348 -270.19758)
		(size 0.4572)
		(drill 0.2032)
		(layers "F.Cu" "B.Cu")
		(net "GND")
	)
	(via
		(at 43.520614 -264.466578)
		(size 0.4572)
		(drill 0.2032)
		(layers "F.Cu" "B.Cu")
		(net "GND")
	)
	(via
		(at 330.252578 -54.558946)
		(size 0.4572)
		(drill 0.2032)
		(layers "F.Cu" "B.Cu")
		(net "GND")
	)
	(via
		(at 199.527414 -215.166702)
		(size 0.4572)
		(drill 0.2032)
		(layers "F.Cu" "B.Cu")
		(net "GND")
	)
	(via
		(at 122.558048 -271.011396)
		(size 0.4572)
		(drill 0.2032)
		(layers "F.Cu" "B.Cu")
		(net "GND")
	)
	(via
		(at 132.113274 -407.00452)
		(size 0.4064)
		(drill 0.2032)
		(layers "F.Cu" "B.Cu")
		(net "GND")
	)
	(via
		(at 259.075682 -204.116686)
		(size 0.4572)
		(drill 0.2032)
		(layers "F.Cu" "B.Cu")
		(net "GND")
	)
	(via
		(at 136.075166 -240.667286)
		(size 0.4572)
		(drill 0.2032)
		(layers "F.Cu" "B.Cu")
		(net "GND")
	)
	(via
		(at 433.253642 -402.290534)
		(size 0.508)
		(drill 0.254)
		(layers "F.Cu" "B.Cu")
		(net "GND")
	)
	(via
		(at 374.038368 -331.81163)
		(size 0.508)
		(drill 0.254)
		(layers "F.Cu" "B.Cu")
		(net "GND")
	)
	(via
		(at 62.051946 -199.01662)
		(size 0.4572)
		(drill 0.2032)
		(layers "F.Cu" "B.Cu")
		(net "GND")
	)
	(via
		(at 297.122088 -361.625388)
		(size 0.49022)
		(drill 0.254)
		(layers "F.Cu" "B.Cu")
		(net "GND")
	)
	(via
		(at 191.983614 -271.266666)
		(size 0.4572)
		(drill 0.2032)
		(layers "F.Cu" "B.Cu")
		(net "GND")
	)
	(via
		(at 359.110788 -218.692222)
		(size 0.4572)
		(drill 0.2032)
		(layers "F.Cu" "B.Cu")
		(net "GND")
	)
	(via
		(at 44.754546 -273.816572)
		(size 0.4572)
		(drill 0.2032)
		(layers "F.Cu" "B.Cu")
		(net "GND")
	)
	(via
		(at 306.017422 -435.596538)
		(size 0.508)
		(drill 0.254)
		(layers "F.Cu" "B.Cu")
		(net "GND")
	)
	(via
		(at 123.027948 -276.708616)
		(size 0.4572)
		(drill 0.2032)
		(layers "F.Cu" "B.Cu")
		(net "GND")
	)
	(via
		(at 349.822262 -284.033722)
		(size 0.4572)
		(drill 0.2032)
		(layers "F.Cu" "B.Cu")
		(net "GND")
	)
	(via
		(at 134.305548 -270.19758)
		(size 0.4572)
		(drill 0.2032)
		(layers "F.Cu" "B.Cu")
		(net "GND")
	)
	(via
		(at 356.400862 -272.639282)
		(size 0.4572)
		(drill 0.2032)
		(layers "F.Cu" "B.Cu")
		(net "GND")
	)
	(via
		(at 292.694614 -268.71676)
		(size 0.4572)
		(drill 0.2032)
		(layers "F.Cu" "B.Cu")
		(net "GND")
	)
	(via
		(at 423.214292 -397.651478)
		(size 0.508)
		(drill 0.254)
		(layers "F.Cu" "B.Cu")
		(net "GND")
	)
	(via
		(at 339.374734 -243.108988)
		(size 0.4572)
		(drill 0.2032)
		(layers "F.Cu" "B.Cu")
		(net "GND")
	)
	(via
		(at 58.23077 -401.492212)
		(size 0.4572)
		(drill 0.254)
		(layers "F.Cu" "B.Cu")
		(net "GND")
	)
	(via
		(at 96.243394 -262.872474)
		(size 0.4572)
		(drill 0.2032)
		(layers "F.Cu" "B.Cu")
		(net "GND")
	)
	(via
		(at 70.571106 -406.370536)
		(size 0.4572)
		(drill 0.254)
		(layers "F.Cu" "B.Cu")
		(net "GND")
	)
	(via
		(at 359.11028 -225.203258)
		(size 0.4572)
		(drill 0.2032)
		(layers "F.Cu" "B.Cu")
		(net "GND")
	)
	(via
		(at 392.129772 -19.125438)
		(size 0.508)
		(drill 0.254)
		(layers "F.Cu" "B.Cu")
		(net "GND")
	)
	(via
		(at 212.724746 -289.11677)
		(size 0.4572)
		(drill 0.2032)
		(layers "F.Cu" "B.Cu")
		(net "GND")
	)
	(via
		(at 458.455014 -309.51678)
		(size 0.4572)
		(drill 0.2032)
		(layers "F.Cu" "B.Cu")
		(net "GND")
	)
	(via
		(at 363.36605 -259.63499)
		(size 0.4572)
		(drill 0.2032)
		(layers "F.Cu" "B.Cu")
		(net "GND")
	)
	(via
		(at 270.063214 -300.166786)
		(size 0.4572)
		(drill 0.2032)
		(layers "F.Cu" "B.Cu")
		(net "GND")
	)
	(via
		(at 450.911214 -309.51678)
		(size 0.4572)
		(drill 0.2032)
		(layers "F.Cu" "B.Cu")
		(net "GND")
	)
	(via
		(at 103.652066 -334.282034)
		(size 0.49022)
		(drill 0.254)
		(layers "F.Cu" "B.Cu")
		(net "GND")
	)
	(via
		(at 394.349986 -438.651396)
		(size 0.4572)
		(drill 0.2032)
		(layers "F.Cu" "B.Cu")
		(net "GND")
	)
	(via
		(at 351.077276 -406.370536)
		(size 0.4572)
		(drill 0.254)
		(layers "F.Cu" "B.Cu")
		(net "GND")
	)
	(via
		(at 202.971146 -233.016806)
		(size 0.4572)
		(drill 0.2032)
		(layers "F.Cu" "B.Cu")
		(net "GND")
	)
	(via
		(at 165.252146 -309.51678)
		(size 0.4572)
		(drill 0.2032)
		(layers "F.Cu" "B.Cu")
		(net "GND")
	)
	(via
		(at 179.105814 -210.066636)
		(size 0.4572)
		(drill 0.2032)
		(layers "F.Cu" "B.Cu")
		(net "GND")
	)
	(via
		(at 53.547518 -400.858228)
		(size 0.4064)
		(drill 0.2032)
		(layers "F.Cu" "B.Cu")
		(net "GND")
	)
	(via
		(at 39.45509 -17.61236)
		(size 0.508)
		(drill 0.254)
		(layers "F.Cu" "B.Cu")
		(net "GND")
	)
	(via
		(at 7.035546 -276.366732)
		(size 0.4572)
		(drill 0.2032)
		(layers "F.Cu" "B.Cu")
		(net "GND")
	)
	(via
		(at 379.895862 -287.28924)
		(size 0.4572)
		(drill 0.2032)
		(layers "F.Cu" "B.Cu")
		(net "GND")
	)
	(via
		(at 114.18189 -12.544552)
		(size 0.508)
		(drill 0.254)
		(layers "F.Cu" "B.Cu")
		(net "GND")
	)
	(via
		(at 387.904228 -342.557354)
		(size 0.49022)
		(drill 0.254)
		(layers "F.Cu" "B.Cu")
		(net "GND")
	)
	(via
		(at 53.44287 -351.612708)
		(size 0.49022)
		(drill 0.254)
		(layers "F.Cu" "B.Cu")
		(net "GND")
	)
	(via
		(at 289.250882 -226.216718)
		(size 0.4572)
		(drill 0.2032)
		(layers "F.Cu" "B.Cu")
		(net "GND")
	)
	(via
		(at 88.590882 -337.692238)
		(size 0.49022)
		(drill 0.254)
		(layers "F.Cu" "B.Cu")
		(net "GND")
	)
	(via
		(at 420.736014 -229.616762)
		(size 0.4572)
		(drill 0.2032)
		(layers "F.Cu" "B.Cu")
		(net "GND")
	)
	(via
		(at 7.035546 -204.96657)
		(size 0.4572)
		(drill 0.2032)
		(layers "F.Cu" "B.Cu")
		(net "GND")
	)
	(via
		(at 339.014816 -273.453098)
		(size 0.4572)
		(drill 0.2032)
		(layers "F.Cu" "B.Cu")
		(net "GND")
	)
	(via
		(at 93.894148 -260.430772)
		(size 0.4572)
		(drill 0.2032)
		(layers "F.Cu" "B.Cu")
		(net "GND")
	)
	(via
		(at 72.6186 -6.086348)
		(size 0.508)
		(drill 0.254)
		(layers "F.Cu" "B.Cu")
		(net "GND")
	)
	(via
		(at 168.0337 -11.463782)
		(size 0.508)
		(drill 0.254)
		(layers "F.Cu" "B.Cu")
		(net "GND")
	)
	(via
		(at 165.78072 -22.786848)
		(size 0.508)
		(drill 0.254)
		(layers "F.Cu" "B.Cu")
		(net "GND")
	)
	(via
		(at 376.966734 -213.732618)
		(size 0.4572)
		(drill 0.2032)
		(layers "F.Cu" "B.Cu")
		(net "GND")
	)
	(via
		(at 157.975046 -400.224244)
		(size 0.4572)
		(drill 0.254)
		(layers "F.Cu" "B.Cu")
		(net "GND")
	)
	(via
		(at 294.904414 -212.616796)
		(size 0.4572)
		(drill 0.2032)
		(layers "F.Cu" "B.Cu")
		(net "GND")
	)
	(via
		(at 371.662706 -178.178968)
		(size 0.508)
		(drill 0.254)
		(layers "F.Cu" "B.Cu")
		(net "GND")
	)
	(via
		(at 294.904414 -295.06672)
		(size 0.4572)
		(drill 0.2032)
		(layers "F.Cu" "B.Cu")
		(net "GND")
	)
	(via
		(at 18.679414 -247.466612)
		(size 0.4572)
		(drill 0.2032)
		(layers "F.Cu" "B.Cu")
		(net "GND")
	)
	(via
		(at 55.260494 -165.133274)
		(size 0.49022)
		(drill 0.254)
		(layers "F.Cu" "B.Cu")
		(net "GND")
	)
	(via
		(at 464.764882 -295.916604)
		(size 0.4572)
		(drill 0.2032)
		(layers "F.Cu" "B.Cu")
		(net "GND")
	)
	(via
		(at 300.238414 -285.716726)
		(size 0.4572)
		(drill 0.2032)
		(layers "F.Cu" "B.Cu")
		(net "GND")
	)
	(via
		(at 187.883546 -265.316716)
		(size 0.4572)
		(drill 0.2032)
		(layers "F.Cu" "B.Cu")
		(net "GND")
	)
	(via
		(at 194.193414 -272.966688)
		(size 0.4572)
		(drill 0.2032)
		(layers "F.Cu" "B.Cu")
		(net "GND")
	)
	(via
		(at 314.092082 -202.416664)
		(size 0.4572)
		(drill 0.2032)
		(layers "F.Cu" "B.Cu")
		(net "GND")
	)
	(via
		(at 7.035546 -246.616728)
		(size 0.4572)
		(drill 0.2032)
		(layers "F.Cu" "B.Cu")
		(net "GND")
	)
	(via
		(at 147.73783 -59.273948)
		(size 0.508)
		(drill 0.254)
		(layers "F.Cu" "B.Cu")
		(net "GND")
	)
	(via
		(at 99.3521 -113.106708)
		(size 0.508)
		(drill 0.254)
		(layers "F.Cu" "B.Cu")
		(net "GND")
	)
	(via
		(at 293.297356 -355.16693)
		(size 0.508)
		(drill 0.254)
		(layers "F.Cu" "B.Cu")
		(net "GND")
	)
	(via
		(at 439.923682 -310.366664)
		(size 0.4572)
		(drill 0.2032)
		(layers "F.Cu" "B.Cu")
		(net "GND")
	)
	(via
		(at 274.163282 -310.366664)
		(size 0.4572)
		(drill 0.2032)
		(layers "F.Cu" "B.Cu")
		(net "GND")
	)
	(via
		(at 29.666692 -410.784548)
		(size 0.508)
		(drill 0.254)
		(layers "F.Cu" "B.Cu")
		(net "GND")
	)
	(via
		(at 417.292282 -226.216718)
		(size 0.4572)
		(drill 0.2032)
		(layers "F.Cu" "B.Cu")
		(net "GND")
	)
	(via
		(at 38.003734 -179.53609)
		(size 0.508)
		(drill 0.254)
		(layers "F.Cu" "B.Cu")
		(net "GND")
	)
	(via
		(at 6.2738 -194.4624)
		(size 0.508)
		(drill 0.254)
		(layers "F.Cu" "B.Cu")
		(net "GND")
	)
	(via
		(at 132.425694 -266.941808)
		(size 0.4572)
		(drill 0.2032)
		(layers "F.Cu" "B.Cu")
		(net "GND")
	)
	(via
		(at 101.5492 -15.154148)
		(size 0.508)
		(drill 0.254)
		(layers "F.Cu" "B.Cu")
		(net "GND")
	)
	(via
		(at 43.520614 -294.216582)
		(size 0.4572)
		(drill 0.2032)
		(layers "F.Cu" "B.Cu")
		(net "GND")
	)
	(via
		(at 413.192214 -258.516628)
		(size 0.4572)
		(drill 0.2032)
		(layers "F.Cu" "B.Cu")
		(net "GND")
	)
	(via
		(at 417.292282 -239.81664)
		(size 0.4572)
		(drill 0.2032)
		(layers "F.Cu" "B.Cu")
		(net "GND")
	)
	(via
		(at 22.123146 -287.416748)
		(size 0.4572)
		(drill 0.2032)
		(layers "F.Cu" "B.Cu")
		(net "GND")
	)
	(via
		(at 63.942214 -245.76659)
		(size 0.4572)
		(drill 0.2032)
		(layers "F.Cu" "B.Cu")
		(net "GND")
	)
	(via
		(at 270.063214 -281.466798)
		(size 0.4572)
		(drill 0.2032)
		(layers "F.Cu" "B.Cu")
		(net "GND")
	)
	(via
		(at 384.955034 -235.783882)
		(size 0.4318)
		(drill 0.2032)
		(layers "F.Cu" "B.Cu")
		(net "GND")
	)
	(via
		(at 292.694614 -199.01662)
		(size 0.4572)
		(drill 0.2032)
		(layers "F.Cu" "B.Cu")
		(net "GND")
	)
	(via
		(at 265.3919 -422.2877)
		(size 0.508)
		(drill 0.254)
		(layers "F.Cu" "B.Cu")
		(net "GND")
	)
	(via
		(at 126.382272 -100.998528)
		(size 0.508)
		(drill 0.254)
		(layers "F.Cu" "B.Cu")
		(net "GND")
	)
	(via
		(at 335.761076 -406.370536)
		(size 0.4572)
		(drill 0.254)
		(layers "F.Cu" "B.Cu")
		(net "GND")
	)
	(via
		(at 182.549546 -300.166786)
		(size 0.4572)
		(drill 0.2032)
		(layers "F.Cu" "B.Cu")
		(net "GND")
	)
	(via
		(at 389.335772 -17.601438)
		(size 0.508)
		(drill 0.254)
		(layers "F.Cu" "B.Cu")
		(net "GND")
	)
	(via
		(at 341.526368 -410.030168)
		(size 0.4064)
		(drill 0.2032)
		(layers "F.Cu" "B.Cu")
		(net "GND")
	)
	(via
		(at 122.917712 -240.667286)
		(size 0.4572)
		(drill 0.2032)
		(layers "F.Cu" "B.Cu")
		(net "GND")
	)
	(via
		(at 314.092082 -308.666642)
		(size 0.4572)
		(drill 0.2032)
		(layers "F.Cu" "B.Cu")
		(net "GND")
	)
	(via
		(at 21.01469 -182.359046)
		(size 0.508)
		(drill 0.254)
		(layers "F.Cu" "B.Cu")
		(net "GND")
	)
	(via
		(at 207.071214 -219.41663)
		(size 0.4572)
		(drill 0.2032)
		(layers "F.Cu" "B.Cu")
		(net "GND")
	)
	(via
		(at 157.708346 -210.916774)
		(size 0.4572)
		(drill 0.2032)
		(layers "F.Cu" "B.Cu")
		(net "GND")
	)
	(via
		(at 407.858214 -260.21665)
		(size 0.4572)
		(drill 0.2032)
		(layers "F.Cu" "B.Cu")
		(net "GND")
	)
	(via
		(at 390.349994 -431.451258)
		(size 0.4572)
		(drill 0.2032)
		(layers "F.Cu" "B.Cu")
		(net "GND")
	)
	(via
		(at 162.49523 -438.495948)
		(size 0.508)
		(drill 0.254)
		(layers "F.Cu" "B.Cu")
		(net "GND")
	)
	(via
		(at 94.364048 -279.150318)
		(size 0.4572)
		(drill 0.2032)
		(layers "F.Cu" "B.Cu")
		(net "GND")
	)
	(via
		(at 29.666946 -304.416714)
		(size 0.4572)
		(drill 0.2032)
		(layers "F.Cu" "B.Cu")
		(net "GND")
	)
	(via
		(at 184.439814 -205.816708)
		(size 0.4572)
		(drill 0.2032)
		(layers "F.Cu" "B.Cu")
		(net "GND")
	)
	(via
		(at 175.005746 -283.166566)
		(size 0.4572)
		(drill 0.2032)
		(layers "F.Cu" "B.Cu")
		(net "GND")
	)
	(via
		(at 409.243022 -400.224244)
		(size 0.4572)
		(drill 0.254)
		(layers "F.Cu" "B.Cu")
		(net "GND")
	)
	(via
		(at 118.88216 -420.320978)
		(size 0.508)
		(drill 0.254)
		(layers "F.Cu" "B.Cu")
		(net "GND")
	)
	(via
		(at 145.51533 -441.225432)
		(size 0.508)
		(drill 0.254)
		(layers "F.Cu" "B.Cu")
		(net "GND")
	)
	(via
		(at 138.894566 -221.133924)
		(size 0.4572)
		(drill 0.2032)
		(layers "F.Cu" "B.Cu")
		(net "GND")
	)
	(via
		(at 427.045882 -222.816674)
		(size 0.4572)
		(drill 0.2032)
		(layers "F.Cu" "B.Cu")
		(net "GND")
	)
	(via
		(at 178.289204 -55.79999)
		(size 0.508)
		(drill 0.254)
		(layers "F.Cu" "B.Cu")
		(net "GND")
	)
	(via
		(at 163.8681 -17.655032)
		(size 0.508)
		(drill 0.254)
		(layers "F.Cu" "B.Cu")
		(net "GND")
	)
	(via
		(at 375.557034 -229.272846)
		(size 0.4572)
		(drill 0.2032)
		(layers "F.Cu" "B.Cu")
		(net "GND")
	)
	(via
		(at 296.794682 -202.416664)
		(size 0.4572)
		(drill 0.2032)
		(layers "F.Cu" "B.Cu")
		(net "GND")
	)
	(via
		(at 370.665248 -86.64702)
		(size 0.508)
		(drill 0.254)
		(layers "F.Cu" "B.Cu")
		(net "GND")
	)
	(via
		(at 334.76438 -335.976214)
		(size 0.49022)
		(drill 0.254)
		(layers "F.Cu" "B.Cu")
		(net "GND")
	)
	(via
		(at 344.906092 -332.56601)
		(size 0.49022)
		(drill 0.254)
		(layers "F.Cu" "B.Cu")
		(net "GND")
	)
	(via
		(at 28.961334 -170.029886)
		(size 0.508)
		(drill 0.254)
		(layers "F.Cu" "B.Cu")
		(net "GND")
	)
	(via
		(at 167.461946 -223.666558)
		(size 0.4572)
		(drill 0.2032)
		(layers "F.Cu" "B.Cu")
		(net "GND")
	)
	(via
		(at 370.388134 -239.853216)
		(size 0.4572)
		(drill 0.2032)
		(layers "F.Cu" "B.Cu")
		(net "GND")
	)
	(via
		(at 58.608214 -264.466578)
		(size 0.4572)
		(drill 0.2032)
		(layers "F.Cu" "B.Cu")
		(net "GND")
	)
	(via
		(at 259.075682 -262.76681)
		(size 0.4572)
		(drill 0.2032)
		(layers "F.Cu" "B.Cu")
		(net "GND")
	)
	(via
		(at 460.664814 -307.816758)
		(size 0.4572)
		(drill 0.2032)
		(layers "F.Cu" "B.Cu")
		(net "GND")
	)
	(via
		(at 164.018214 -213.46668)
		(size 0.4572)
		(drill 0.2032)
		(layers "F.Cu" "B.Cu")
		(net "GND")
	)
	(via
		(at 202.971146 -258.516628)
		(size 0.4572)
		(drill 0.2032)
		(layers "F.Cu" "B.Cu")
		(net "GND")
	)
	(via
		(at 306.548282 -205.816708)
		(size 0.4572)
		(drill 0.2032)
		(layers "F.Cu" "B.Cu")
		(net "GND")
	)
	(via
		(at 346.72016 -363.510068)
		(size 0.508)
		(drill 0.254)
		(layers "F.Cu" "B.Cu")
		(net "GND")
	)
	(via
		(at 22.123146 -295.06672)
		(size 0.4572)
		(drill 0.2032)
		(layers "F.Cu" "B.Cu")
		(net "GND")
	)
	(via
		(at 98.439478 -331.776832)
		(size 0.49022)
		(drill 0.254)
		(layers "F.Cu" "B.Cu")
		(net "GND")
	)
	(via
		(at 99.422966 -239.0394)
		(size 0.4572)
		(drill 0.2032)
		(layers "F.Cu" "B.Cu")
		(net "GND")
	)
	(via
		(at 259.075682 -269.566644)
		(size 0.4572)
		(drill 0.2032)
		(layers "F.Cu" "B.Cu")
		(net "GND")
	)
	(via
		(at 356.77602 -55.884572)
		(size 0.508)
		(drill 0.254)
		(layers "F.Cu" "B.Cu")
		(net "GND")
	)
	(via
		(at 349.556832 -329.722226)
		(size 0.508)
		(drill 0.254)
		(layers "F.Cu" "B.Cu")
		(net "GND")
	)
	(via
		(at 41.8211 -6.597396)
		(size 0.508)
		(drill 0.254)
		(layers "F.Cu" "B.Cu")
		(net "GND")
	)
	(via
		(at 234.860338 -133.809232)
		(size 0.508)
		(drill 0.254)
		(layers "F.Cu" "B.Cu")
		(net "GND")
	)
	(via
		(at 0.76454 -71.960232)
		(size 0.508)
		(drill 0.254)
		(layers "F.Cu" "B.Cu")
		(net "GND")
	)
	(via
		(at 460.664814 -223.666558)
		(size 0.4572)
		(drill 0.2032)
		(layers "F.Cu" "B.Cu")
		(net "GND")
	)
	(via
		(at 401.349972 -427.699678)
		(size 0.4572)
		(drill 0.2032)
		(layers "F.Cu" "B.Cu")
		(net "GND")
	)
	(via
		(at 185.278522 -345.750896)
		(size 0.508)
		(drill 0.254)
		(layers "F.Cu" "B.Cu")
		(net "GND")
	)
	(via
		(at 302.448214 -281.466798)
		(size 0.4572)
		(drill 0.2032)
		(layers "F.Cu" "B.Cu")
		(net "GND")
	)
	(via
		(at 346.423234 -227.64496)
		(size 0.4572)
		(drill 0.2032)
		(layers "F.Cu" "B.Cu")
		(net "GND")
	)
	(via
		(at 353.066604 -332.56601)
		(size 0.49022)
		(drill 0.254)
		(layers "F.Cu" "B.Cu")
		(net "GND")
	)
	(via
		(at 387.620764 -333.453232)
		(size 0.508)
		(drill 0.254)
		(layers "F.Cu" "B.Cu")
		(net "GND")
	)
	(via
		(at 378.956062 -261.244842)
		(size 0.4572)
		(drill 0.2032)
		(layers "F.Cu" "B.Cu")
		(net "GND")
	)
	(via
		(at 216.872312 -67.324478)
		(size 0.508)
		(drill 0.254)
		(layers "F.Cu" "B.Cu")
		(net "GND")
	)
	(via
		(at 129.966212 -239.853216)
		(size 0.4572)
		(drill 0.2032)
		(layers "F.Cu" "B.Cu")
		(net "GND")
	)
	(via
		(at 442.133482 -216.866724)
		(size 0.4572)
		(drill 0.2032)
		(layers "F.Cu" "B.Cu")
		(net "GND")
	)
	(via
		(at 24.332946 -306.116736)
		(size 0.4572)
		(drill 0.2032)
		(layers "F.Cu" "B.Cu")
		(net "GND")
	)
	(via
		(at 130.436366 -226.017328)
		(size 0.4572)
		(drill 0.2032)
		(layers "F.Cu" "B.Cu")
		(net "GND")
	)
	(via
		(at 464.764882 -244.066568)
		(size 0.4572)
		(drill 0.2032)
		(layers "F.Cu" "B.Cu")
		(net "GND")
	)
	(via
		(at 262.519414 -268.71676)
		(size 0.4572)
		(drill 0.2032)
		(layers "F.Cu" "B.Cu")
		(net "GND")
	)
	(via
		(at 279.816814 -279.766776)
		(size 0.4572)
		(drill 0.2032)
		(layers "F.Cu" "B.Cu")
		(net "GND")
	)
	(via
		(at 99.595432 -401.995386)
		(size 0.508)
		(drill 0.254)
		(layers "F.Cu" "B.Cu")
		(net "GND")
	)
	(via
		(at 122.917966 -219.506038)
		(size 0.4572)
		(drill 0.2032)
		(layers "F.Cu" "B.Cu")
		(net "GND")
	)
	(via
		(at 370.86413 -400.858228)
		(size 0.4064)
		(drill 0.2032)
		(layers "F.Cu" "B.Cu")
		(net "GND")
	)
	(via
		(at 305.128676 -406.370536)
		(size 0.4572)
		(drill 0.254)
		(layers "F.Cu" "B.Cu")
		(net "GND")
	)
	(via
		(at 133.195314 -407.00452)
		(size 0.4064)
		(drill 0.2032)
		(layers "F.Cu" "B.Cu")
		(net "GND")
	)
	(via
		(at 335.255362 -270.19758)
		(size 0.4572)
		(drill 0.2032)
		(layers "F.Cu" "B.Cu")
		(net "GND")
	)
	(via
		(at 137.768838 -341.766906)
		(size 0.49022)
		(drill 0.254)
		(layers "F.Cu" "B.Cu")
		(net "GND")
	)
	(via
		(at 22.123146 -309.51678)
		(size 0.4572)
		(drill 0.2032)
		(layers "F.Cu" "B.Cu")
		(net "GND")
	)
	(via
		(at 439.923682 -297.616626)
		(size 0.4572)
		(drill 0.2032)
		(layers "F.Cu" "B.Cu")
		(net "GND")
	)
	(via
		(at 412.990792 -358.705912)
		(size 0.508)
		(drill 0.254)
		(layers "F.Cu" "B.Cu")
		(net "GND")
	)
	(via
		(at 194.193414 -200.716642)
		(size 0.4572)
		(drill 0.2032)
		(layers "F.Cu" "B.Cu")
		(net "GND")
	)
	(via
		(at 286.762952 -323.429376)
		(size 0.4572)
		(drill 0.2032)
		(layers "F.Cu" "B.Cu")
		(net "GND")
	)
	(via
		(at 119.738648 -288.917126)
		(size 0.4572)
		(drill 0.2032)
		(layers "F.Cu" "B.Cu")
		(net "GND")
	)
	(via
		(at 346.416884 -71.081392)
		(size 0.508)
		(drill 0.254)
		(layers "F.Cu" "B.Cu")
		(net "GND")
	)
	(via
		(at 299.004482 -247.466612)
		(size 0.4572)
		(drill 0.2032)
		(layers "F.Cu" "B.Cu")
		(net "GND")
	)
	(via
		(at 132.26034 -150.508208)
		(size 0.508)
		(drill 0.254)
		(layers "F.Cu" "B.Cu")
		(net "GND")
	)
	(via
		(at 259.075682 -249.166634)
		(size 0.4572)
		(drill 0.2032)
		(layers "F.Cu" "B.Cu")
		(net "GND")
	)
	(via
		(at 348.882716 -275.8948)
		(size 0.4572)
		(drill 0.2032)
		(layers "F.Cu" "B.Cu")
		(net "GND")
	)
	(via
		(at 16.789146 -199.01662)
		(size 0.4572)
		(drill 0.2032)
		(layers "F.Cu" "B.Cu")
		(net "GND")
	)
	(via
		(at 261.285482 -202.416664)
		(size 0.4572)
		(drill 0.2032)
		(layers "F.Cu" "B.Cu")
		(net "GND")
	)
	(via
		(at 39.237158 -345.642438)
		(size 0.508)
		(drill 0.254)
		(layers "F.Cu" "B.Cu")
		(net "GND")
	)
	(via
		(at 264.729214 -317.166752)
		(size 0.4572)
		(drill 0.2032)
		(layers "F.Cu" "B.Cu")
		(net "GND")
	)
	(via
		(at 380.835662 -280.778204)
		(size 0.4572)
		(drill 0.2032)
		(layers "F.Cu" "B.Cu")
		(net "GND")
	)
	(via
		(at 85.905594 -257.98907)
		(size 0.4572)
		(drill 0.2032)
		(layers "F.Cu" "B.Cu")
		(net "GND")
	)
	(via
		(at 254.975614 -197.316598)
		(size 0.4572)
		(drill 0.2032)
		(layers "F.Cu" "B.Cu")
		(net "GND")
	)
	(via
		(at 362.979462 -264.50036)
		(size 0.4572)
		(drill 0.2032)
		(layers "F.Cu" "B.Cu")
		(net "GND")
	)
	(via
		(at 124.34697 -331.08392)
		(size 0.508)
		(drill 0.254)
		(layers "F.Cu" "B.Cu")
		(net "GND")
	)
	(via
		(at 266.619482 -245.76659)
		(size 0.4572)
		(drill 0.2032)
		(layers "F.Cu" "B.Cu")
		(net "GND")
	)
	(via
		(at 345.123262 -287.28924)
		(size 0.4572)
		(drill 0.2032)
		(layers "F.Cu" "B.Cu")
		(net "GND")
	)
	(via
		(at 287.360614 -307.816758)
		(size 0.4572)
		(drill 0.2032)
		(layers "F.Cu" "B.Cu")
		(net "GND")
	)
	(via
		(at 432.093624 -18.491454)
		(size 0.508)
		(drill 0.254)
		(layers "F.Cu" "B.Cu")
		(net "GND")
	)
	(via
		(at 90.25001 -437.34736)
		(size 0.4572)
		(drill 0.2032)
		(layers "F.Cu" "B.Cu")
		(net "GND")
	)
	(via
		(at 131.486148 -278.336502)
		(size 0.4572)
		(drill 0.2032)
		(layers "F.Cu" "B.Cu")
		(net "GND")
	)
	(via
		(at 159.321246 -406.370536)
		(size 0.4572)
		(drill 0.254)
		(layers "F.Cu" "B.Cu")
		(net "GND")
	)
	(via
		(at 363.271816 -368.811556)
		(size 0.508)
		(drill 0.254)
		(layers "F.Cu" "B.Cu")
		(net "GND")
	)
	(via
		(at 124.327412 -236.597952)
		(size 0.4572)
		(drill 0.2032)
		(layers "F.Cu" "B.Cu")
		(net "GND")
	)
	(via
		(at 167.768016 -234.716574)
		(size 0.4572)
		(drill 0.2032)
		(layers "F.Cu" "B.Cu")
		(net "GND")
	)
	(via
		(at 415.656014 -220.266768)
		(size 0.4572)
		(drill 0.2032)
		(layers "F.Cu" "B.Cu")
		(net "GND")
	)
	(via
		(at 41.6306 -103.977948)
		(size 0.508)
		(drill 0.254)
		(layers "F.Cu" "B.Cu")
		(net "GND")
	)
	(via
		(at 188.63437 -427.319948)
		(size 0.508)
		(drill 0.254)
		(layers "F.Cu" "B.Cu")
		(net "GND")
	)
	(via
		(at 97.653094 -266.941808)
		(size 0.4572)
		(drill 0.2032)
		(layers "F.Cu" "B.Cu")
		(net "GND")
	)
	(via
		(at 342.66378 -239.0394)
		(size 0.4572)
		(drill 0.2032)
		(layers "F.Cu" "B.Cu")
		(net "GND")
	)
	(via
		(at 46.964346 -281.466798)
		(size 0.4572)
		(drill 0.2032)
		(layers "F.Cu" "B.Cu")
		(net "GND")
	)
	(via
		(at 300.238414 -265.316716)
		(size 0.4572)
		(drill 0.2032)
		(layers "F.Cu" "B.Cu")
		(net "GND")
	)
	(via
		(at 370.62029 -365.665258)
		(size 0.508)
		(drill 0.254)
		(layers "F.Cu" "B.Cu")
		(net "GND")
	)
	(via
		(at 447.467482 -221.116652)
		(size 0.4572)
		(drill 0.2032)
		(layers "F.Cu" "B.Cu")
		(net "GND")
	)
	(via
		(at 181.314344 -326.057006)
		(size 0.508)
		(drill 0.254)
		(layers "F.Cu" "B.Cu")
		(net "GND")
	)
	(via
		(at 335.14538 -243.922804)
		(size 0.4318)
		(drill 0.2032)
		(layers "F.Cu" "B.Cu")
		(net "GND")
	)
	(via
		(at 35.976814 -316.316614)
		(size 0.4572)
		(drill 0.2032)
		(layers "F.Cu" "B.Cu")
		(net "GND")
	)
	(via
		(at 63.942214 -196.466714)
		(size 0.4572)
		(drill 0.2032)
		(layers "F.Cu" "B.Cu")
		(net "GND")
	)
	(via
		(at 370.028216 -266.941808)
		(size 0.4572)
		(drill 0.2032)
		(layers "F.Cu" "B.Cu")
		(net "GND")
	)
	(via
		(at 194.193414 -245.76659)
		(size 0.4572)
		(drill 0.2032)
		(layers "F.Cu" "B.Cu")
		(net "GND")
	)
	(via
		(at 126.317248 -280.778204)
		(size 0.4572)
		(drill 0.2032)
		(layers "F.Cu" "B.Cu")
		(net "GND")
	)
	(via
		(at 171.7675 -355.538278)
		(size 0.49022)
		(drill 0.254)
		(layers "F.Cu" "B.Cu")
		(net "GND")
	)
	(via
		(at 306.845716 -403.249892)
		(size 0.4572)
		(drill 0.254)
		(layers "F.Cu" "B.Cu")
		(net "GND")
	)
	(via
		(at 32.350964 -390.10717)
		(size 0.508)
		(drill 0.254)
		(layers "F.Cu" "B.Cu")
		(net "GND")
	)
	(via
		(at 306.3875 -407.638504)
		(size 0.4572)
		(drill 0.254)
		(layers "F.Cu" "B.Cu")
		(net "GND")
	)
	(via
		(at 24.332946 -238.966756)
		(size 0.4572)
		(drill 0.2032)
		(layers "F.Cu" "B.Cu")
		(net "GND")
	)
	(via
		(at 429.764952 -395.798548)
		(size 0.508)
		(drill 0.254)
		(layers "F.Cu" "B.Cu")
		(net "GND")
	)
	(via
		(at 327.250044 -429.147224)
		(size 0.4572)
		(drill 0.2032)
		(layers "F.Cu" "B.Cu")
		(net "GND")
	)
	(via
		(at 48.854614 -226.216718)
		(size 0.4572)
		(drill 0.2032)
		(layers "F.Cu" "B.Cu")
		(net "GND")
	)
	(via
		(at 294.62222 -417.990528)
		(size 0.508)
		(drill 0.254)
		(layers "F.Cu" "B.Cu")
		(net "GND")
	)
	(via
		(at 180.955696 -110.975394)
		(size 0.4572)
		(drill 0.254)
		(layers "F.Cu" "B.Cu")
		(net "GND")
	)
	(via
		(at 100.942394 -282.405836)
		(size 0.4572)
		(drill 0.2032)
		(layers "F.Cu" "B.Cu")
		(net "GND")
	)
	(via
		(at 21.348192 -400.814032)
		(size 0.508)
		(drill 0.254)
		(layers "F.Cu" "B.Cu")
		(net "GND")
	)
	(via
		(at 18.679414 -266.1666)
		(size 0.4572)
		(drill 0.2032)
		(layers "F.Cu" "B.Cu")
		(net "GND")
	)
	(via
		(at 285.150814 -270.416782)
		(size 0.4572)
		(drill 0.2032)
		(layers "F.Cu" "B.Cu")
		(net "GND")
	)
	(via
		(at 358.027732 -38.594792)
		(size 0.508)
		(drill 0.254)
		(layers "F.Cu" "B.Cu")
		(net "GND")
	)
	(via
		(at 343.13368 -234.970066)
		(size 0.4572)
		(drill 0.2032)
		(layers "F.Cu" "B.Cu")
		(net "GND")
	)
	(via
		(at 156.619194 -410.030168)
		(size 0.4064)
		(drill 0.2032)
		(layers "F.Cu" "B.Cu")
		(net "GND")
	)
	(via
		(at 207.071214 -196.466714)
		(size 0.4572)
		(drill 0.2032)
		(layers "F.Cu" "B.Cu")
		(net "GND")
	)
	(via
		(at 385.048252 -340.977728)
		(size 0.49022)
		(drill 0.254)
		(layers "F.Cu" "B.Cu")
		(net "GND")
	)
	(via
		(at 384.350006 -439.651394)
		(size 0.4572)
		(drill 0.2032)
		(layers "F.Cu" "B.Cu")
		(net "GND")
	)
	(via
		(at 366.269016 -284.847538)
		(size 0.4572)
		(drill 0.2032)
		(layers "F.Cu" "B.Cu")
		(net "GND")
	)
	(via
		(at 21.799804 -106.761026)
		(size 0.508)
		(drill 0.254)
		(layers "F.Cu" "B.Cu")
		(net "GND")
	)
	(via
		(at 29.666946 -201.56678)
		(size 0.4572)
		(drill 0.2032)
		(layers "F.Cu" "B.Cu")
		(net "GND")
	)
	(via
		(at 85.887306 -406.370536)
		(size 0.4572)
		(drill 0.254)
		(layers "F.Cu" "B.Cu")
		(net "GND")
	)
	(via
		(at 88.145366 -245.55069)
		(size 0.4572)
		(drill 0.2032)
		(layers "F.Cu" "B.Cu")
		(net "GND")
	)
	(via
		(at 447.467482 -226.216718)
		(size 0.4572)
		(drill 0.2032)
		(layers "F.Cu" "B.Cu")
		(net "GND")
	)
	(via
		(at 443.367414 -283.166566)
		(size 0.4572)
		(drill 0.2032)
		(layers "F.Cu" "B.Cu")
		(net "GND")
	)
	(via
		(at 22.123146 -263.616694)
		(size 0.4572)
		(drill 0.2032)
		(layers "F.Cu" "B.Cu")
		(net "GND")
	)
	(via
		(at 62.64021 -410.664152)
		(size 0.4572)
		(drill 0.254)
		(layers "F.Cu" "B.Cu")
		(net "GND")
	)
	(via
		(at 134.195566 -239.0394)
		(size 0.4572)
		(drill 0.2032)
		(layers "F.Cu" "B.Cu")
		(net "GND")
	)
	(via
		(at 137.878566 -407.638504)
		(size 0.4572)
		(drill 0.254)
		(layers "F.Cu" "B.Cu")
		(net "GND")
	)
	(via
		(at 100.472748 -265.314176)
		(size 0.4572)
		(drill 0.2032)
		(layers "F.Cu" "B.Cu")
		(net "GND")
	)
	(via
		(at 96.305878 -331.776832)
		(size 0.49022)
		(drill 0.254)
		(layers "F.Cu" "B.Cu")
		(net "GND")
	)
	(via
		(at 113.072418 -334.282034)
		(size 0.49022)
		(drill 0.254)
		(layers "F.Cu" "B.Cu")
		(net "GND")
	)
	(via
		(at 371.608604 -331.780896)
		(size 0.49022)
		(drill 0.254)
		(layers "F.Cu" "B.Cu")
		(net "GND")
	)
	(via
		(at 345.593416 -258.80314)
		(size 0.4572)
		(drill 0.2032)
		(layers "F.Cu" "B.Cu")
		(net "GND")
	)
	(via
		(at 434.589682 -303.566576)
		(size 0.4572)
		(drill 0.2032)
		(layers "F.Cu" "B.Cu")
		(net "GND")
	)
	(via
		(at 394.014198 -407.638504)
		(size 0.4572)
		(drill 0.254)
		(layers "F.Cu" "B.Cu")
		(net "GND")
	)
	(via
		(at 268.829282 -262.76681)
		(size 0.4572)
		(drill 0.2032)
		(layers "F.Cu" "B.Cu")
		(net "GND")
	)
	(via
		(at 172.795946 -279.766776)
		(size 0.4572)
		(drill 0.2032)
		(layers "F.Cu" "B.Cu")
		(net "GND")
	)
	(via
		(at 109.473746 -326.836532)
		(size 0.508)
		(drill 0.254)
		(layers "F.Cu" "B.Cu")
		(net "GND")
	)
	(via
		(at 291.460682 -247.466612)
		(size 0.4572)
		(drill 0.2032)
		(layers "F.Cu" "B.Cu")
		(net "GND")
	)
	(via
		(at 287.912048 -364.759494)
		(size 0.49022)
		(drill 0.254)
		(layers "F.Cu" "B.Cu")
		(net "GND")
	)
	(via
		(at 167.461946 -203.266802)
		(size 0.4572)
		(drill 0.2032)
		(layers "F.Cu" "B.Cu")
		(net "GND")
	)
	(via
		(at 435.823614 -268.71676)
		(size 0.4572)
		(drill 0.2032)
		(layers "F.Cu" "B.Cu")
		(net "GND")
	)
	(via
		(at 384.124962 -258.80314)
		(size 0.4572)
		(drill 0.2032)
		(layers "F.Cu" "B.Cu")
		(net "GND")
	)
	(via
		(at 309.992014 -246.616728)
		(size 0.4572)
		(drill 0.2032)
		(layers "F.Cu" "B.Cu")
		(net "GND")
	)
	(via
		(at 9.245346 -296.766742)
		(size 0.4572)
		(drill 0.2032)
		(layers "F.Cu" "B.Cu")
		(net "GND")
	)
	(via
		(at 102.352348 -278.336502)
		(size 0.4572)
		(drill 0.2032)
		(layers "F.Cu" "B.Cu")
		(net "GND")
	)
	(via
		(at 140.54709 -17.655032)
		(size 0.508)
		(drill 0.254)
		(layers "F.Cu" "B.Cu")
		(net "GND")
	)
	(via
		(at 167.252142 -409.396184)
		(size 0.4572)
		(drill 0.254)
		(layers "F.Cu" "B.Cu")
		(net "GND")
	)
	(via
		(at 407.858214 -223.666558)
		(size 0.4572)
		(drill 0.2032)
		(layers "F.Cu" "B.Cu")
		(net "GND")
	)
	(via
		(at 29.666946 -197.316598)
		(size 0.4572)
		(drill 0.2032)
		(layers "F.Cu" "B.Cu")
		(net "GND")
	)
	(via
		(at 174.352204 -345.648788)
		(size 0.508)
		(drill 0.254)
		(layers "F.Cu" "B.Cu")
		(net "GND")
	)
	(via
		(at 399.349976 -430.299622)
		(size 0.4572)
		(drill 0.2032)
		(layers "F.Cu" "B.Cu")
		(net "GND")
	)
	(via
		(at 55.30596 -6.597396)
		(size 0.508)
		(drill 0.254)
		(layers "F.Cu" "B.Cu")
		(net "GND")
	)
	(via
		(at 420.736014 -233.016806)
		(size 0.4572)
		(drill 0.2032)
		(layers "F.Cu" "B.Cu")
		(net "GND")
	)
	(via
		(at 74.407268 -17.148302)
		(size 0.508)
		(drill 0.254)
		(layers "F.Cu" "B.Cu")
		(net "GND")
	)
	(via
		(at 51.064414 -205.816708)
		(size 0.4572)
		(drill 0.2032)
		(layers "F.Cu" "B.Cu")
		(net "GND")
	)
	(via
		(at 455.011282 -245.76659)
		(size 0.4572)
		(drill 0.2032)
		(layers "F.Cu" "B.Cu")
		(net "GND")
	)
	(via
		(at 368.918744 -256.666746)
		(size 0.4572)
		(drill 0.2032)
		(layers "F.Cu" "B.Cu")
		(net "GND")
	)
	(via
		(at 22.123146 -290.816792)
		(size 0.4572)
		(drill 0.2032)
		(layers "F.Cu" "B.Cu")
		(net "GND")
	)
	(via
		(at 457.221082 -233.86669)
		(size 0.4572)
		(drill 0.2032)
		(layers "F.Cu" "B.Cu")
		(net "GND")
	)
	(via
		(at 161.808414 -213.46668)
		(size 0.4572)
		(drill 0.2032)
		(layers "F.Cu" "B.Cu")
		(net "GND")
	)
	(via
		(at 283.916882 -247.466612)
		(size 0.4572)
		(drill 0.2032)
		(layers "F.Cu" "B.Cu")
		(net "GND")
	)
	(via
		(at 106.673396 -356.943406)
		(size 0.508)
		(drill 0.254)
		(layers "F.Cu" "B.Cu")
		(net "GND")
	)
	(via
		(at 395.13129 -5.585714)
		(size 0.508)
		(drill 0.254)
		(layers "F.Cu" "B.Cu")
		(net "GND")
	)
	(via
		(at 287.360614 -204.96657)
		(size 0.4572)
		(drill 0.2032)
		(layers "F.Cu" "B.Cu")
		(net "GND")
	)
	(via
		(at 353.941634 -219.506038)
		(size 0.4572)
		(drill 0.2032)
		(layers "F.Cu" "B.Cu")
		(net "GND")
	)
	(via
		(at 67.250056 -426.69968)
		(size 0.4572)
		(drill 0.2032)
		(layers "F.Cu" "B.Cu")
		(net "GND")
	)
	(via
		(at 417.292282 -221.116652)
		(size 0.4572)
		(drill 0.2032)
		(layers "F.Cu" "B.Cu")
		(net "GND")
	)
	(via
		(at 283.916882 -299.316648)
		(size 0.4572)
		(drill 0.2032)
		(layers "F.Cu" "B.Cu")
		(net "GND")
	)
	(via
		(at 25.3365 -396.107412)
		(size 0.508)
		(drill 0.254)
		(layers "F.Cu" "B.Cu")
		(net "GND")
	)
	(via
		(at 283.916882 -289.966654)
		(size 0.4572)
		(drill 0.2032)
		(layers "F.Cu" "B.Cu")
		(net "GND")
	)
	(via
		(at 279.816814 -197.316598)
		(size 0.4572)
		(drill 0.2032)
		(layers "F.Cu" "B.Cu")
		(net "GND")
	)
	(via
		(at 450.06641 -31.976822)
		(size 0.508)
		(drill 0.254)
		(layers "F.Cu" "B.Cu")
		(net "GND")
	)
	(via
		(at 316.822582 -30.987746)
		(size 0.508)
		(drill 0.254)
		(layers "F.Cu" "B.Cu")
		(net "GND")
	)
	(via
		(at 304.1396 -418.069268)
		(size 0.508)
		(drill 0.254)
		(layers "F.Cu" "B.Cu")
		(net "GND")
	)
	(via
		(at 139.364466 -230.086662)
		(size 0.4572)
		(drill 0.2032)
		(layers "F.Cu" "B.Cu")
		(net "GND")
	)
	(via
		(at 417.292282 -194.766692)
		(size 0.4572)
		(drill 0.2032)
		(layers "F.Cu" "B.Cu")
		(net "GND")
	)
	(via
		(at 272.273014 -206.666592)
		(size 0.4572)
		(drill 0.2032)
		(layers "F.Cu" "B.Cu")
		(net "GND")
	)
	(via
		(at 420.736014 -270.416782)
		(size 0.4572)
		(drill 0.2032)
		(layers "F.Cu" "B.Cu")
		(net "GND")
	)
	(via
		(at 26.138886 -166.395908)
		(size 0.508)
		(drill 0.254)
		(layers "F.Cu" "B.Cu")
		(net "GND")
	)
	(via
		(at 164.018214 -291.666676)
		(size 0.4572)
		(drill 0.2032)
		(layers "F.Cu" "B.Cu")
		(net "GND")
	)
	(via
		(at 413.192214 -197.316598)
		(size 0.4572)
		(drill 0.2032)
		(layers "F.Cu" "B.Cu")
		(net "GND")
	)
	(via
		(at 38.030912 -384.779012)
		(size 0.508)
		(drill 0.254)
		(layers "F.Cu" "B.Cu")
		(net "GND")
	)
	(via
		(at 91.434412 -246.364506)
		(size 0.4572)
		(drill 0.2032)
		(layers "F.Cu" "B.Cu")
		(net "GND")
	)
	(via
		(at 47.21733 -392.183366)
		(size 0.508)
		(drill 0.254)
		(layers "F.Cu" "B.Cu")
		(net "GND")
	)
	(via
		(at 462.555082 -261.066788)
		(size 0.4572)
		(drill 0.2032)
		(layers "F.Cu" "B.Cu")
		(net "GND")
	)
	(via
		(at 340.444328 -410.030168)
		(size 0.4064)
		(drill 0.2032)
		(layers "F.Cu" "B.Cu")
		(net "GND")
	)
	(via
		(at 292.694614 -217.716608)
		(size 0.4572)
		(drill 0.2032)
		(layers "F.Cu" "B.Cu")
		(net "GND")
	)
	(via
		(at 29.666946 -260.21665)
		(size 0.4572)
		(drill 0.2032)
		(layers "F.Cu" "B.Cu")
		(net "GND")
	)
	(via
		(at 299.004482 -239.81664)
		(size 0.4572)
		(drill 0.2032)
		(layers "F.Cu" "B.Cu")
		(net "GND")
	)
	(via
		(at 133.365494 -255.547622)
		(size 0.4572)
		(drill 0.2032)
		(layers "F.Cu" "B.Cu")
		(net "GND")
	)
	(via
		(at 128.28397 -351.104454)
		(size 0.508)
		(drill 0.254)
		(layers "F.Cu" "B.Cu")
		(net "GND")
	)
	(via
		(at 109.77753 -329.061826)
		(size 0.508)
		(drill 0.254)
		(layers "F.Cu" "B.Cu")
		(net "GND")
	)
	(via
		(at 363.322616 -249.226832)
		(size 0.4572)
		(drill 0.2032)
		(layers "F.Cu" "B.Cu")
		(net "GND")
	)
	(via
		(at 429.764952 -380.568962)
		(size 0.508)
		(drill 0.254)
		(layers "F.Cu" "B.Cu")
		(net "GND")
	)
	(via
		(at 111.812578 -334.282034)
		(size 0.49022)
		(drill 0.254)
		(layers "F.Cu" "B.Cu")
		(net "GND")
	)
	(via
		(at 212.724746 -250.016772)
		(size 0.4572)
		(drill 0.2032)
		(layers "F.Cu" "B.Cu")
		(net "GND")
	)
	(via
		(at 365.219234 -222.761556)
		(size 0.4572)
		(drill 0.2032)
		(layers "F.Cu" "B.Cu")
		(net "GND")
	)
	(via
		(at 134.349998 -436.347362)
		(size 0.4572)
		(drill 0.2032)
		(layers "F.Cu" "B.Cu")
		(net "GND")
	)
	(via
		(at 43.520614 -299.316648)
		(size 0.4572)
		(drill 0.2032)
		(layers "F.Cu" "B.Cu")
		(net "GND")
	)
	(via
		(at 347.876622 -37.455348)
		(size 0.49022)
		(drill 0.254)
		(layers "F.Cu" "B.Cu")
		(net "GND")
	)
	(via
		(at 297.60037 -364.759494)
		(size 0.49022)
		(drill 0.254)
		(layers "F.Cu" "B.Cu")
		(net "GND")
	)
	(via
		(at 298.795948 -161.563304)
		(size 0.508)
		(drill 0.254)
		(layers "F.Cu" "B.Cu")
		(net "GND")
	)
	(via
		(at 335.615534 -228.45903)
		(size 0.4572)
		(drill 0.2032)
		(layers "F.Cu" "B.Cu")
		(net "GND")
	)
	(via
		(at 101.772212 -243.108988)
		(size 0.4572)
		(drill 0.2032)
		(layers "F.Cu" "B.Cu")
		(net "GND")
	)
	(via
		(at 279.816814 -272.116804)
		(size 0.4572)
		(drill 0.2032)
		(layers "F.Cu" "B.Cu")
		(net "GND")
	)
	(via
		(at 238.60252 -388.01294)
		(size 0.508)
		(drill 0.254)
		(layers "F.Cu" "B.Cu")
		(net "GND")
	)
	(via
		(at 292.694614 -263.616694)
		(size 0.4572)
		(drill 0.2032)
		(layers "F.Cu" "B.Cu")
		(net "GND")
	)
	(via
		(at 18.54708 -9.424924)
		(size 0.508)
		(drill 0.254)
		(layers "F.Cu" "B.Cu")
		(net "GND")
	)
	(via
		(at 430.97704 -122.988578)
		(size 0.508)
		(drill 0.254)
		(layers "F.Cu" "B.Cu")
		(net "GND")
	)
	(via
		(at 447.98742 -376.100848)
		(size 0.49022)
		(drill 0.254)
		(layers "F.Cu" "B.Cu")
		(net "GND")
	)
	(via
		(at 333.95666 -409.396184)
		(size 0.4572)
		(drill 0.254)
		(layers "F.Cu" "B.Cu")
		(net "GND")
	)
	(via
		(at 48.638714 -235.566712)
		(size 0.4572)
		(drill 0.2032)
		(layers "F.Cu" "B.Cu")
		(net "GND")
	)
	(via
		(at 381.305562 -275.08073)
		(size 0.4572)
		(drill 0.2032)
		(layers "F.Cu" "B.Cu")
		(net "GND")
	)
	(via
		(at 328.648822 -60.442348)
		(size 0.508)
		(drill 0.254)
		(layers "F.Cu" "B.Cu")
		(net "GND")
	)
	(via
		(at 126.098554 -331.81163)
		(size 0.508)
		(drill 0.254)
		(layers "F.Cu" "B.Cu")
		(net "GND")
	)
	(via
		(at 175.005746 -212.616796)
		(size 0.4572)
		(drill 0.2032)
		(layers "F.Cu" "B.Cu")
		(net "GND")
	)
	(via
		(at 97.66554 -111.420148)
		(size 0.508)
		(drill 0.254)
		(layers "F.Cu" "B.Cu")
		(net "GND")
	)
	(via
		(at 340.784434 -248.806208)
		(size 0.4572)
		(drill 0.2032)
		(layers "F.Cu" "B.Cu")
		(net "GND")
	)
	(via
		(at 447.467482 -312.91657)
		(size 0.4572)
		(drill 0.2032)
		(layers "F.Cu" "B.Cu")
		(net "GND")
	)
	(via
		(at 38.812724 -359.20045)
		(size 0.508)
		(drill 0.254)
		(layers "F.Cu" "B.Cu")
		(net "GND")
	)
	(via
		(at 430.489614 -231.316784)
		(size 0.4572)
		(drill 0.2032)
		(layers "F.Cu" "B.Cu")
		(net "GND")
	)
	(via
		(at 86.265766 -247.178322)
		(size 0.4572)
		(drill 0.2032)
		(layers "F.Cu" "B.Cu")
		(net "GND")
	)
	(via
		(at 88.145366 -243.922804)
		(size 0.4572)
		(drill 0.2032)
		(layers "F.Cu" "B.Cu")
		(net "GND")
	)
	(via
		(at 242.871752 -129.408936)
		(size 0.508)
		(drill 0.254)
		(layers "F.Cu" "B.Cu")
		(net "GND")
	)
	(via
		(at 414.659064 -364.071662)
		(size 0.49022)
		(drill 0.254)
		(layers "F.Cu" "B.Cu")
		(net "GND")
	)
	(via
		(at 349.71228 -244.73662)
		(size 0.4572)
		(drill 0.2032)
		(layers "F.Cu" "B.Cu")
		(net "GND")
	)
	(via
		(at 439.923682 -205.816708)
		(size 0.4572)
		(drill 0.2032)
		(layers "F.Cu" "B.Cu")
		(net "GND")
	)
	(via
		(at 264.729214 -263.616694)
		(size 0.4572)
		(drill 0.2032)
		(layers "F.Cu" "B.Cu")
		(net "GND")
	)
	(via
		(at 402.046948 -10.16508)
		(size 0.508)
		(drill 0.254)
		(layers "F.Cu" "B.Cu")
		(net "GND")
	)
	(via
		(at 97.97288 -82.235294)
		(size 0.508)
		(drill 0.254)
		(layers "F.Cu" "B.Cu")
		(net "GND")
	)
	(via
		(at 348.77248 -247.992138)
		(size 0.4572)
		(drill 0.2032)
		(layers "F.Cu" "B.Cu")
		(net "GND")
	)
	(via
		(at 415.624264 -236.416596)
		(size 0.4572)
		(drill 0.2032)
		(layers "F.Cu" "B.Cu")
		(net "GND")
	)
	(via
		(at 386.944616 -275.080984)
		(size 0.4572)
		(drill 0.2032)
		(layers "F.Cu" "B.Cu")
		(net "GND")
	)
	(via
		(at 289.250882 -295.916604)
		(size 0.4572)
		(drill 0.2032)
		(layers "F.Cu" "B.Cu")
		(net "GND")
	)
	(via
		(at 165.60292 -33.990788)
		(size 0.508)
		(drill 0.254)
		(layers "F.Cu" "B.Cu")
		(net "GND")
	)
	(via
		(at 11.135614 -200.716642)
		(size 0.4572)
		(drill 0.2032)
		(layers "F.Cu" "B.Cu")
		(net "GND")
	)
	(via
		(at 360.49458 -414.274)
		(size 0.508)
		(drill 0.254)
		(layers "F.Cu" "B.Cu")
		(net "GND")
	)
	(via
		(at 341.834216 -255.547622)
		(size 0.4572)
		(drill 0.2032)
		(layers "F.Cu" "B.Cu")
		(net "GND")
	)
	(via
		(at 157.708346 -258.516628)
		(size 0.4572)
		(drill 0.2032)
		(layers "F.Cu" "B.Cu")
		(net "GND")
	)
	(via
		(at 202.971146 -246.616728)
		(size 0.4572)
		(drill 0.2032)
		(layers "F.Cu" "B.Cu")
		(net "GND")
	)
	(via
		(at 39.420546 -223.666558)
		(size 0.4572)
		(drill 0.2032)
		(layers "F.Cu" "B.Cu")
		(net "GND")
	)
	(via
		(at 151.935942 -407.638504)
		(size 0.4572)
		(drill 0.254)
		(layers "F.Cu" "B.Cu")
		(net "GND")
	)
	(via
		(at 194.463924 -11.403076)
		(size 0.508)
		(drill 0.254)
		(layers "F.Cu" "B.Cu")
		(net "GND")
	)
	(via
		(at 46.376082 -19.770344)
		(size 0.508)
		(drill 0.254)
		(layers "F.Cu" "B.Cu")
		(net "GND")
	)
	(via
		(at 272.273014 -216.016586)
		(size 0.4572)
		(drill 0.2032)
		(layers "F.Cu" "B.Cu")
		(net "GND")
	)
	(via
		(at 413.336486 -174.363126)
		(size 0.508)
		(drill 0.254)
		(layers "F.Cu" "B.Cu")
		(net "GND")
	)
	(via
		(at 132.425694 -253.919736)
		(size 0.4572)
		(drill 0.2032)
		(layers "F.Cu" "B.Cu")
		(net "GND")
	)
	(via
		(at 385.065016 -255.547368)
		(size 0.4318)
		(drill 0.2032)
		(layers "F.Cu" "B.Cu")
		(net "GND")
	)
	(via
		(at 347.652848 -407.00452)
		(size 0.4064)
		(drill 0.2032)
		(layers "F.Cu" "B.Cu")
		(net "GND")
	)
	(via
		(at 420.736014 -248.31675)
		(size 0.4572)
		(drill 0.2032)
		(layers "F.Cu" "B.Cu")
		(net "GND")
	)
	(via
		(at 291.460682 -301.01667)
		(size 0.4572)
		(drill 0.2032)
		(layers "F.Cu" "B.Cu")
		(net "GND")
	)
	(via
		(at 127.703834 -400.858228)
		(size 0.4064)
		(drill 0.2032)
		(layers "F.Cu" "B.Cu")
		(net "GND")
	)
	(via
		(at 169.352214 -198.166736)
		(size 0.4572)
		(drill 0.2032)
		(layers "F.Cu" "B.Cu")
		(net "GND")
	)
	(via
		(at 268.829282 -249.166634)
		(size 0.4572)
		(drill 0.2032)
		(layers "F.Cu" "B.Cu")
		(net "GND")
	)
	(via
		(at 435.606952 -388.73303)
		(size 0.508)
		(drill 0.254)
		(layers "F.Cu" "B.Cu")
		(net "GND")
	)
	(via
		(at 88.250014 -431.451258)
		(size 0.4572)
		(drill 0.2032)
		(layers "F.Cu" "B.Cu")
		(net "GND")
	)
	(via
		(at 121.978166 -226.017328)
		(size 0.4572)
		(drill 0.2032)
		(layers "F.Cu" "B.Cu")
		(net "GND")
	)
	(via
		(at 411.958282 -303.566576)
		(size 0.4572)
		(drill 0.2032)
		(layers "F.Cu" "B.Cu")
		(net "GND")
	)
	(via
		(at 88.255094 -268.569694)
		(size 0.4572)
		(drill 0.2032)
		(layers "F.Cu" "B.Cu")
		(net "GND")
	)
	(via
		(at 55.41645 -350.255332)
		(size 0.508)
		(drill 0.254)
		(layers "F.Cu" "B.Cu")
		(net "GND")
	)
	(via
		(at 382.35001 -438.651396)
		(size 0.4572)
		(drill 0.2032)
		(layers "F.Cu" "B.Cu")
		(net "GND")
	)
	(via
		(at 96.133412 -228.45903)
		(size 0.4572)
		(drill 0.2032)
		(layers "F.Cu" "B.Cu")
		(net "GND")
	)
	(via
		(at 175.005746 -261.916672)
		(size 0.4572)
		(drill 0.2032)
		(layers "F.Cu" "B.Cu")
		(net "GND")
	)
	(via
		(at 108.013246 -85.867494)
		(size 0.508)
		(drill 0.254)
		(layers "F.Cu" "B.Cu")
		(net "GND")
	)
	(via
		(at 91.434666 -226.831144)
		(size 0.4572)
		(drill 0.2032)
		(layers "F.Cu" "B.Cu")
		(net "GND")
	)
	(via
		(at 332.971648 -403.883876)
		(size 0.4064)
		(drill 0.2032)
		(layers "F.Cu" "B.Cu")
		(net "GND")
	)
	(via
		(at 428.279814 -261.916672)
		(size 0.4572)
		(drill 0.2032)
		(layers "F.Cu" "B.Cu")
		(net "GND")
	)
	(via
		(at 335.241646 -277.244302)
		(size 0.4572)
		(drill 0.2032)
		(layers "F.Cu" "B.Cu")
		(net "GND")
	)
	(via
		(at 321.250056 -427.699678)
		(size 0.4572)
		(drill 0.2032)
		(layers "F.Cu" "B.Cu")
		(net "GND")
	)
	(via
		(at 257.185414 -292.516814)
		(size 0.4572)
		(drill 0.2032)
		(layers "F.Cu" "B.Cu")
		(net "GND")
	)
	(via
		(at 332.971648 -400.858228)
		(size 0.4064)
		(drill 0.2032)
		(layers "F.Cu" "B.Cu")
		(net "GND")
	)
	(via
		(at 81.477866 -404.51786)
		(size 0.4572)
		(drill 0.254)
		(layers "F.Cu" "B.Cu")
		(net "GND")
	)
	(via
		(at 139.488418 -337.72475)
		(size 0.6604)
		(drill 0.3302)
		(layers "F.Cu" "B.Cu")
		(net "GND")
	)
	(via
		(at 98.592894 -286.475424)
		(size 0.4572)
		(drill 0.2032)
		(layers "F.Cu" "B.Cu")
		(net "GND")
	)
	(via
		(at 101.772212 -244.73662)
		(size 0.4572)
		(drill 0.2032)
		(layers "F.Cu" "B.Cu")
		(net "GND")
	)
	(via
		(at 126.786894 -275.08073)
		(size 0.4572)
		(drill 0.2032)
		(layers "F.Cu" "B.Cu")
		(net "GND")
	)
	(via
		(at 33.767014 -284.866588)
		(size 0.4572)
		(drill 0.2032)
		(layers "F.Cu" "B.Cu")
		(net "GND")
	)
	(via
		(at 309.992014 -240.666778)
		(size 0.4572)
		(drill 0.2032)
		(layers "F.Cu" "B.Cu")
		(net "GND")
	)
	(via
		(at 127.52578 -107.895898)
		(size 0.508)
		(drill 0.254)
		(layers "F.Cu" "B.Cu")
		(net "GND")
	)
	(via
		(at 190.093346 -199.01662)
		(size 0.4572)
		(drill 0.2032)
		(layers "F.Cu" "B.Cu")
		(net "GND")
	)
	(via
		(at 312.090816 -28.478988)
		(size 0.508)
		(drill 0.254)
		(layers "F.Cu" "B.Cu")
		(net "GND")
	)
	(via
		(at 46.964346 -270.416782)
		(size 0.4572)
		(drill 0.2032)
		(layers "F.Cu" "B.Cu")
		(net "GND")
	)
	(via
		(at 456.606402 -68.471034)
		(size 0.508)
		(drill 0.254)
		(layers "F.Cu" "B.Cu")
		(net "GND")
	)
	(via
		(at 380.43358 -186.055508)
		(size 0.508)
		(drill 0.254)
		(layers "F.Cu" "B.Cu")
		(net "GND")
	)
	(via
		(at 372.629684 -331.71892)
		(size 0.508)
		(drill 0.254)
		(layers "F.Cu" "B.Cu")
		(net "GND")
	)
	(via
		(at 407.858214 -270.416782)
		(size 0.4572)
		(drill 0.2032)
		(layers "F.Cu" "B.Cu")
		(net "GND")
	)
	(via
		(at 291.460682 -204.116686)
		(size 0.4572)
		(drill 0.2032)
		(layers "F.Cu" "B.Cu")
		(net "GND")
	)
	(via
		(at 385.493768 -343.48293)
		(size 0.49022)
		(drill 0.254)
		(layers "F.Cu" "B.Cu")
		(net "GND")
	)
	(via
		(at 2.764536 -244.270022)
		(size 0.508)
		(drill 0.254)
		(layers "F.Cu" "B.Cu")
		(net "GND")
	)
	(via
		(at 316.035436 -404.51786)
		(size 0.4572)
		(drill 0.254)
		(layers "F.Cu" "B.Cu")
		(net "GND")
	)
	(via
		(at 84.385912 -237.411768)
		(size 0.4572)
		(drill 0.2032)
		(layers "F.Cu" "B.Cu")
		(net "GND")
	)
	(via
		(at 216.824814 -207.51673)
		(size 0.4572)
		(drill 0.2032)
		(layers "F.Cu" "B.Cu")
		(net "GND")
	)
	(via
		(at 350.65208 -231.714548)
		(size 0.4572)
		(drill 0.2032)
		(layers "F.Cu" "B.Cu")
		(net "GND")
	)
	(via
		(at 435.40172 -39.31666)
		(size 0.508)
		(drill 0.254)
		(layers "F.Cu" "B.Cu")
		(net "GND")
	)
	(via
		(at 441.073032 -34.266378)
		(size 0.508)
		(drill 0.254)
		(layers "F.Cu" "B.Cu")
		(net "GND")
	)
	(via
		(at 264.729214 -261.916672)
		(size 0.4572)
		(drill 0.2032)
		(layers "F.Cu" "B.Cu")
		(net "GND")
	)
	(via
		(at 21.90623 -429.351948)
		(size 0.508)
		(drill 0.254)
		(layers "F.Cu" "B.Cu")
		(net "GND")
	)
	(via
		(at 375.90857 -400.858228)
		(size 0.4064)
		(drill 0.2032)
		(layers "F.Cu" "B.Cu")
		(net "GND")
	)
	(via
		(at 104.701594 -284.033722)
		(size 0.4572)
		(drill 0.2032)
		(layers "F.Cu" "B.Cu")
		(net "GND")
	)
	(via
		(at 359.11028 -238.225584)
		(size 0.4572)
		(drill 0.2032)
		(layers "F.Cu" "B.Cu")
		(net "GND")
	)
	(via
		(at 174.281084 -323.434456)
		(size 0.4572)
		(drill 0.2032)
		(layers "F.Cu" "B.Cu")
		(net "GND")
	)
	(via
		(at 89.63533 -441.225432)
		(size 0.508)
		(drill 0.254)
		(layers "F.Cu" "B.Cu")
		(net "GND")
	)
	(via
		(at 460.664814 -203.266802)
		(size 0.4572)
		(drill 0.2032)
		(layers "F.Cu" "B.Cu")
		(net "GND")
	)
	(via
		(at 326.080374 -37.87521)
		(size 0.49022)
		(drill 0.254)
		(layers "F.Cu" "B.Cu")
		(net "GND")
	)
	(via
		(at 88.596216 -342.106758)
		(size 0.508)
		(drill 0.254)
		(layers "F.Cu" "B.Cu")
		(net "GND")
	)
	(via
		(at 370.952014 -407.020014)
		(size 0.508)
		(drill 0.254)
		(layers "F.Cu" "B.Cu")
		(net "GND")
	)
	(via
		(at 98.482912 -232.528364)
		(size 0.4572)
		(drill 0.2032)
		(layers "F.Cu" "B.Cu")
		(net "GND")
	)
	(via
		(at 139.474448 -262.872474)
		(size 0.4572)
		(drill 0.2032)
		(layers "F.Cu" "B.Cu")
		(net "GND")
	)
	(via
		(at 377.259596 -357.355394)
		(size 0.508)
		(drill 0.254)
		(layers "F.Cu" "B.Cu")
		(net "GND")
	)
	(via
		(at 382.35001 -426.69968)
		(size 0.4572)
		(drill 0.2032)
		(layers "F.Cu" "B.Cu")
		(net "GND")
	)
	(via
		(at 161.038286 -403.249892)
		(size 0.4572)
		(drill 0.254)
		(layers "F.Cu" "B.Cu")
		(net "GND")
	)
	(via
		(at 372.737634 -219.506038)
		(size 0.4572)
		(drill 0.2032)
		(layers "F.Cu" "B.Cu")
		(net "GND")
	)
	(via
		(at 186.649614 -262.76681)
		(size 0.4572)
		(drill 0.2032)
		(layers "F.Cu" "B.Cu")
		(net "GND")
	)
	(via
		(at 462.555082 -204.116686)
		(size 0.4572)
		(drill 0.2032)
		(layers "F.Cu" "B.Cu")
		(net "GND")
	)
	(via
		(at 209.281014 -235.566712)
		(size 0.4572)
		(drill 0.2032)
		(layers "F.Cu" "B.Cu")
		(net "GND")
	)
	(via
		(at 98.122994 -256.361438)
		(size 0.4572)
		(drill 0.2032)
		(layers "F.Cu" "B.Cu")
		(net "GND")
	)
	(via
		(at 417.292282 -228.766624)
		(size 0.4572)
		(drill 0.2032)
		(layers "F.Cu" "B.Cu")
		(net "GND")
	)
	(via
		(at 126.786894 -283.219906)
		(size 0.4572)
		(drill 0.2032)
		(layers "F.Cu" "B.Cu")
		(net "GND")
	)
	(via
		(at 272.285714 -319.344548)
		(size 0.4572)
		(drill 0.2032)
		(layers "F.Cu" "B.Cu")
		(net "GND")
	)
	(via
		(at 415.402014 -204.96657)
		(size 0.4572)
		(drill 0.2032)
		(layers "F.Cu" "B.Cu")
		(net "GND")
	)
	(via
		(at 343.604596 -401.492212)
		(size 0.4572)
		(drill 0.254)
		(layers "F.Cu" "B.Cu")
		(net "GND")
	)
	(via
		(at 199.527414 -226.216718)
		(size 0.4572)
		(drill 0.2032)
		(layers "F.Cu" "B.Cu")
		(net "GND")
	)
	(via
		(at 369.172744 -335.704434)
		(size 0.49022)
		(drill 0.254)
		(layers "F.Cu" "B.Cu")
		(net "GND")
	)
	(via
		(at 419.749986 -216.866724)
		(size 0.4572)
		(drill 0.2032)
		(layers "F.Cu" "B.Cu")
		(net "GND")
	)
	(via
		(at 180.339746 -227.066602)
		(size 0.4572)
		(drill 0.2032)
		(layers "F.Cu" "B.Cu")
		(net "GND")
	)
	(via
		(at 127.726948 -263.686544)
		(size 0.4572)
		(drill 0.2032)
		(layers "F.Cu" "B.Cu")
		(net "GND")
	)
	(via
		(at 383.545334 -246.364506)
		(size 0.4572)
		(drill 0.2032)
		(layers "F.Cu" "B.Cu")
		(net "GND")
	)
	(via
		(at 205.180946 -258.516628)
		(size 0.4572)
		(drill 0.2032)
		(layers "F.Cu" "B.Cu")
		(net "GND")
	)
	(via
		(at 435.823614 -261.916672)
		(size 0.4572)
		(drill 0.2032)
		(layers "F.Cu" "B.Cu")
		(net "GND")
	)
	(via
		(at 419.502082 -266.1666)
		(size 0.4572)
		(drill 0.2032)
		(layers "F.Cu" "B.Cu")
		(net "GND")
	)
	(via
		(at 74.08164 -5.497068)
		(size 0.508)
		(drill 0.254)
		(layers "F.Cu" "B.Cu")
		(net "GND")
	)
	(via
		(at 434.589682 -264.466578)
		(size 0.4572)
		(drill 0.2032)
		(layers "F.Cu" "B.Cu")
		(net "GND")
	)
	(via
		(at 12.5095 -100.668328)
		(size 0.508)
		(drill 0.254)
		(layers "F.Cu" "B.Cu")
		(net "GND")
	)
	(via
		(at 424.836082 -303.566576)
		(size 0.4572)
		(drill 0.2032)
		(layers "F.Cu" "B.Cu")
		(net "GND")
	)
	(via
		(at 336.555334 -220.319854)
		(size 0.4572)
		(drill 0.2032)
		(layers "F.Cu" "B.Cu")
		(net "GND")
	)
	(via
		(at 428.03826 -360.152442)
		(size 0.49022)
		(drill 0.254)
		(layers "F.Cu" "B.Cu")
		(net "GND")
	)
	(via
		(at 165.252146 -223.666558)
		(size 0.4572)
		(drill 0.2032)
		(layers "F.Cu" "B.Cu")
		(net "GND")
	)
	(via
		(at 328.9681 -336.097118)
		(size 0.508)
		(drill 0.254)
		(layers "F.Cu" "B.Cu")
		(net "GND")
	)
	(via
		(at 48.854614 -211.766658)
		(size 0.4572)
		(drill 0.2032)
		(layers "F.Cu" "B.Cu")
		(net "GND")
	)
	(via
		(at 334.25003 -428.851314)
		(size 0.4572)
		(drill 0.2032)
		(layers "F.Cu" "B.Cu")
		(net "GND")
	)
	(via
		(at 37.760402 -352.147378)
		(size 0.508)
		(drill 0.254)
		(layers "F.Cu" "B.Cu")
		(net "GND")
	)
	(via
		(at 187.883546 -221.96679)
		(size 0.4572)
		(drill 0.2032)
		(layers "F.Cu" "B.Cu")
		(net "GND")
	)
	(via
		(at 138.746992 -17.655032)
		(size 0.508)
		(drill 0.254)
		(layers "F.Cu" "B.Cu")
		(net "GND")
	)
	(via
		(at 88.589358 -410.030168)
		(size 0.4064)
		(drill 0.2032)
		(layers "F.Cu" "B.Cu")
		(net "GND")
	)
	(via
		(at 94.833948 -266.941808)
		(size 0.4572)
		(drill 0.2032)
		(layers "F.Cu" "B.Cu")
		(net "GND")
	)
	(via
		(at 87.785194 -269.38351)
		(size 0.4572)
		(drill 0.2032)
		(layers "F.Cu" "B.Cu")
		(net "GND")
	)
	(via
		(at 119.268748 -279.964134)
		(size 0.4572)
		(drill 0.2032)
		(layers "F.Cu" "B.Cu")
		(net "GND")
	)
	(via
		(at 372.377462 -272.639282)
		(size 0.4572)
		(drill 0.2032)
		(layers "F.Cu" "B.Cu")
		(net "GND")
	)
	(via
		(at 136.532366 -401.492212)
		(size 0.4572)
		(drill 0.254)
		(layers "F.Cu" "B.Cu")
		(net "GND")
	)
	(via
		(at 353.111562 -284.847538)
		(size 0.4572)
		(drill 0.2032)
		(layers "F.Cu" "B.Cu")
		(net "GND")
	)
	(via
		(at 405.648414 -311.216802)
		(size 0.4572)
		(drill 0.2032)
		(layers "F.Cu" "B.Cu")
		(net "GND")
	)
	(via
		(at 88.255094 -257.175254)
		(size 0.4572)
		(drill 0.2032)
		(layers "F.Cu" "B.Cu")
		(net "GND")
	)
	(via
		(at 206.71917 -89.918032)
		(size 0.508)
		(drill 0.254)
		(layers "F.Cu" "B.Cu")
		(net "GND")
	)
	(via
		(at 167.461946 -272.116804)
		(size 0.4572)
		(drill 0.2032)
		(layers "F.Cu" "B.Cu")
		(net "GND")
	)
	(via
		(at 467.535514 -98.92538)
		(size 0.508)
		(drill 0.254)
		(layers "F.Cu" "B.Cu")
		(net "GND")
	)
	(via
		(at 64.444626 -409.396184)
		(size 0.4572)
		(drill 0.254)
		(layers "F.Cu" "B.Cu")
		(net "GND")
	)
	(via
		(at 169.352214 -280.61666)
		(size 0.4572)
		(drill 0.2032)
		(layers "F.Cu" "B.Cu")
		(net "GND")
	)
	(via
		(at 336.250026 -433.899564)
		(size 0.4572)
		(drill 0.2032)
		(layers "F.Cu" "B.Cu")
		(net "GND")
	)
	(via
		(at 57.659778 -348.52991)
		(size 0.6604)
		(drill 0.3302)
		(layers "F.Cu" "B.Cu")
		(net "GND")
	)
	(via
		(at 361.569762 -273.453098)
		(size 0.4572)
		(drill 0.2032)
		(layers "F.Cu" "B.Cu")
		(net "GND")
	)
	(via
		(at 96.603566 -226.017328)
		(size 0.4572)
		(drill 0.2032)
		(layers "F.Cu" "B.Cu")
		(net "GND")
	)
	(via
		(at 111.170466 -238.225838)
		(size 0.4572)
		(drill 0.2032)
		(layers "F.Cu" "B.Cu")
		(net "GND")
	)
	(via
		(at 112.092232 -407.074116)
		(size 0.508)
		(drill 0.254)
		(layers "F.Cu" "B.Cu")
		(net "GND")
	)
	(via
		(at 190.093346 -210.916774)
		(size 0.4572)
		(drill 0.2032)
		(layers "F.Cu" "B.Cu")
		(net "GND")
	)
	(via
		(at 257.185414 -221.96679)
		(size 0.4572)
		(drill 0.2032)
		(layers "F.Cu" "B.Cu")
		(net "GND")
	)
	(via
		(at 439.923682 -224.516696)
		(size 0.4572)
		(drill 0.2032)
		(layers "F.Cu" "B.Cu")
		(net "GND")
	)
	(via
		(at 369.438428 -333.355188)
		(size 0.49022)
		(drill 0.254)
		(layers "F.Cu" "B.Cu")
		(net "GND")
	)
	(via
		(at 450.911214 -212.616796)
		(size 0.4572)
		(drill 0.2032)
		(layers "F.Cu" "B.Cu")
		(net "GND")
	)
	(via
		(at 351.085404 -331.776832)
		(size 0.49022)
		(drill 0.254)
		(layers "F.Cu" "B.Cu")
		(net "GND")
	)
	(via
		(at 384.124962 -273.453098)
		(size 0.4572)
		(drill 0.2032)
		(layers "F.Cu" "B.Cu")
		(net "GND")
	)
	(via
		(at 342.194134 -236.597952)
		(size 0.4572)
		(drill 0.2032)
		(layers "F.Cu" "B.Cu")
		(net "GND")
	)
	(via
		(at 192.63868 -113.706148)
		(size 0.508)
		(drill 0.254)
		(layers "F.Cu" "B.Cu")
		(net "GND")
	)
	(via
		(at 37.210746 -304.416714)
		(size 0.4572)
		(drill 0.2032)
		(layers "F.Cu" "B.Cu")
		(net "GND")
	)
	(via
		(at 66.367914 -312.91657)
		(size 0.4572)
		(drill 0.2032)
		(layers "F.Cu" "B.Cu")
		(net "GND")
	)
	(via
		(at 39.987982 -6.090412)
		(size 0.508)
		(drill 0.254)
		(layers "F.Cu" "B.Cu")
		(net "GND")
	)
	(via
		(at 52.082446 -210.916774)
		(size 0.4572)
		(drill 0.2032)
		(layers "F.Cu" "B.Cu")
		(net "GND")
	)
	(via
		(at 209.281014 -269.566644)
		(size 0.4572)
		(drill 0.2032)
		(layers "F.Cu" "B.Cu")
		(net "GND")
	)
	(via
		(at 136.075166 -226.017328)
		(size 0.4572)
		(drill 0.2032)
		(layers "F.Cu" "B.Cu")
		(net "GND")
	)
	(via
		(at 129.136394 -254.733552)
		(size 0.4572)
		(drill 0.2032)
		(layers "F.Cu" "B.Cu")
		(net "GND")
	)
	(via
		(at 457.221082 -316.316614)
		(size 0.4572)
		(drill 0.2032)
		(layers "F.Cu" "B.Cu")
		(net "GND")
	)
	(via
		(at 366.522508 -239.306354)
		(size 0.4572)
		(drill 0.2032)
		(layers "F.Cu" "B.Cu")
		(net "GND")
	)
	(via
		(at 334.675734 -236.597952)
		(size 0.4318)
		(drill 0.2032)
		(layers "F.Cu" "B.Cu")
		(net "GND")
	)
	(via
		(at 416.300158 -4.317746)
		(size 0.508)
		(drill 0.254)
		(layers "F.Cu" "B.Cu")
		(net "GND")
	)
	(via
		(at 217.621104 -32.834072)
		(size 0.508)
		(drill 0.254)
		(layers "F.Cu" "B.Cu")
		(net "GND")
	)
	(via
		(at 120.208548 -279.964134)
		(size 0.4572)
		(drill 0.2032)
		(layers "F.Cu" "B.Cu")
		(net "GND")
	)
	(via
		(at 99.532948 -278.336502)
		(size 0.4572)
		(drill 0.2032)
		(layers "F.Cu" "B.Cu")
		(net "GND")
	)
	(via
		(at 41.792652 -5.596636)
		(size 0.508)
		(drill 0.254)
		(layers "F.Cu" "B.Cu")
		(net "GND")
	)
	(via
		(at 457.221082 -278.916638)
		(size 0.4572)
		(drill 0.2032)
		(layers "F.Cu" "B.Cu")
		(net "GND")
	)
	(via
		(at 118.433088 -246.6594)
		(size 0.4572)
		(drill 0.2032)
		(layers "F.Cu" "B.Cu")
		(net "GND")
	)
	(via
		(at 35.976814 -247.466612)
		(size 0.4572)
		(drill 0.2032)
		(layers "F.Cu" "B.Cu")
		(net "GND")
	)
	(via
		(at 55.254906 -406.370536)
		(size 0.4572)
		(drill 0.254)
		(layers "F.Cu" "B.Cu")
		(net "GND")
	)
	(via
		(at 353.417632 -187.61075)
		(size 0.508)
		(drill 0.254)
		(layers "F.Cu" "B.Cu")
		(net "GND")
	)
	(via
		(at 276.373082 -310.366664)
		(size 0.4572)
		(drill 0.2032)
		(layers "F.Cu" "B.Cu")
		(net "GND")
	)
	(via
		(at 59.842146 -222.04299)
		(size 0.4572)
		(drill 0.2032)
		(layers "F.Cu" "B.Cu")
		(net "GND")
	)
	(via
		(at 106.429048 -93.665548)
		(size 0.508)
		(drill 0.254)
		(layers "F.Cu" "B.Cu")
		(net "GND")
	)
	(via
		(at 59.385962 -159.56788)
		(size 0.508)
		(drill 0.254)
		(layers "F.Cu" "B.Cu")
		(net "GND")
	)
	(via
		(at 167.461946 -295.06672)
		(size 0.4572)
		(drill 0.2032)
		(layers "F.Cu" "B.Cu")
		(net "GND")
	)
	(via
		(at 24.926036 -183.515254)
		(size 0.508)
		(drill 0.254)
		(layers "F.Cu" "B.Cu")
		(net "GND")
	)
	(via
		(at 307.782214 -222.04299)
		(size 0.4572)
		(drill 0.2032)
		(layers "F.Cu" "B.Cu")
		(net "GND")
	)
	(via
		(at 384.350006 -430.147222)
		(size 0.4572)
		(drill 0.2032)
		(layers "F.Cu" "B.Cu")
		(net "GND")
	)
	(via
		(at 378.016262 -267.755878)
		(size 0.4572)
		(drill 0.2032)
		(layers "F.Cu" "B.Cu")
		(net "GND")
	)
	(via
		(at 42.057066 -12.37488)
		(size 0.508)
		(drill 0.254)
		(layers "F.Cu" "B.Cu")
		(net "GND")
	)
	(via
		(at 391.610596 -17.601438)
		(size 0.508)
		(drill 0.254)
		(layers "F.Cu" "B.Cu")
		(net "GND")
	)
	(via
		(at 242.871752 -127.58928)
		(size 0.508)
		(drill 0.254)
		(layers "F.Cu" "B.Cu")
		(net "GND")
	)
	(via
		(at 189.40399 -67.391788)
		(size 0.508)
		(drill 0.254)
		(layers "F.Cu" "B.Cu")
		(net "GND")
	)
	(via
		(at 311.785 -96.6216)
		(size 0.508)
		(drill 0.254)
		(layers "F.Cu" "B.Cu")
		(net "GND")
	)
	(via
		(at 127.39116 -26.708608)
		(size 0.508)
		(drill 0.254)
		(layers "F.Cu" "B.Cu")
		(net "GND")
	)
	(via
		(at 142.658846 -404.51786)
		(size 0.4572)
		(drill 0.254)
		(layers "F.Cu" "B.Cu")
		(net "GND")
	)
	(via
		(at 296.794682 -269.566644)
		(size 0.4572)
		(drill 0.2032)
		(layers "F.Cu" "B.Cu")
		(net "GND")
	)
	(via
		(at 172.795946 -298.466764)
		(size 0.4572)
		(drill 0.2032)
		(layers "F.Cu" "B.Cu")
		(net "GND")
	)
	(via
		(at 428.279814 -231.316784)
		(size 0.4572)
		(drill 0.2032)
		(layers "F.Cu" "B.Cu")
		(net "GND")
	)
	(via
		(at 430.489614 -313.766708)
		(size 0.4572)
		(drill 0.2032)
		(layers "F.Cu" "B.Cu")
		(net "GND")
	)
	(via
		(at 24.332946 -265.316716)
		(size 0.4572)
		(drill 0.2032)
		(layers "F.Cu" "B.Cu")
		(net "GND")
	)
	(via
		(at 380.365762 -271.825212)
		(size 0.4572)
		(drill 0.2032)
		(layers "F.Cu" "B.Cu")
		(net "GND")
	)
	(via
		(at 434.589682 -308.666642)
		(size 0.4572)
		(drill 0.2032)
		(layers "F.Cu" "B.Cu")
		(net "GND")
	)
	(via
		(at 144.005046 -409.396184)
		(size 0.4572)
		(drill 0.254)
		(layers "F.Cu" "B.Cu")
		(net "GND")
	)
	(via
		(at 438.033414 -290.816792)
		(size 0.4572)
		(drill 0.2032)
		(layers "F.Cu" "B.Cu")
		(net "GND")
	)
	(via
		(at 56.398414 -213.46668)
		(size 0.4572)
		(drill 0.2032)
		(layers "F.Cu" "B.Cu")
		(net "GND")
	)
	(via
		(at 114.459766 -216.25052)
		(size 0.4572)
		(drill 0.2032)
		(layers "F.Cu" "B.Cu")
		(net "GND")
	)
	(via
		(at 383.655062 -256.361438)
		(size 0.4572)
		(drill 0.2032)
		(layers "F.Cu" "B.Cu")
		(net "GND")
	)
	(via
		(at 307.782214 -306.116736)
		(size 0.4572)
		(drill 0.2032)
		(layers "F.Cu" "B.Cu")
		(net "GND")
	)
	(via
		(at 113.049812 -215.436704)
		(size 0.4572)
		(drill 0.2032)
		(layers "F.Cu" "B.Cu")
		(net "GND")
	)
	(via
		(at 420.375588 -19.125438)
		(size 0.508)
		(drill 0.254)
		(layers "F.Cu" "B.Cu")
		(net "GND")
	)
	(via
		(at 358.170734 -249.620024)
		(size 0.4572)
		(drill 0.2032)
		(layers "F.Cu" "B.Cu")
		(net "GND")
	)
	(via
		(at 414.756346 -54.105048)
		(size 0.508)
		(drill 0.254)
		(layers "F.Cu" "B.Cu")
		(net "GND")
	)
	(via
		(at 66.367914 -216.866724)
		(size 0.4572)
		(drill 0.2032)
		(layers "F.Cu" "B.Cu")
		(net "GND")
	)
	(via
		(at 405.648414 -244.916706)
		(size 0.4572)
		(drill 0.2032)
		(layers "F.Cu" "B.Cu")
		(net "GND")
	)
	(via
		(at 37.210746 -250.016772)
		(size 0.4572)
		(drill 0.2032)
		(layers "F.Cu" "B.Cu")
		(net "GND")
	)
	(via
		(at 26.223214 -289.966654)
		(size 0.4572)
		(drill 0.2032)
		(layers "F.Cu" "B.Cu")
		(net "GND")
	)
	(via
		(at 409.697682 -271.266666)
		(size 0.4572)
		(drill 0.2032)
		(layers "F.Cu" "B.Cu")
		(net "GND")
	)
	(via
		(at 407.446988 -9.424924)
		(size 0.508)
		(drill 0.254)
		(layers "F.Cu" "B.Cu")
		(net "GND")
	)
	(via
		(at 88.255094 -262.058658)
		(size 0.4572)
		(drill 0.2032)
		(layers "F.Cu" "B.Cu")
		(net "GND")
	)
	(via
		(at 350.652334 -223.575626)
		(size 0.4572)
		(drill 0.2032)
		(layers "F.Cu" "B.Cu")
		(net "GND")
	)
	(via
		(at 179.105814 -266.1666)
		(size 0.4572)
		(drill 0.2032)
		(layers "F.Cu" "B.Cu")
		(net "GND")
	)
	(via
		(at 95.350838 -400.858228)
		(size 0.4064)
		(drill 0.2032)
		(layers "F.Cu" "B.Cu")
		(net "GND")
	)
	(via
		(at 309.992014 -221.96679)
		(size 0.4572)
		(drill 0.2032)
		(layers "F.Cu" "B.Cu")
		(net "GND")
	)
	(via
		(at 272.273014 -301.866808)
		(size 0.4572)
		(drill 0.2032)
		(layers "F.Cu" "B.Cu")
		(net "GND")
	)
	(via
		(at 197.637146 -317.166752)
		(size 0.4572)
		(drill 0.2032)
		(layers "F.Cu" "B.Cu")
		(net "GND")
	)
	(via
		(at 28.433014 -280.61666)
		(size 0.4572)
		(drill 0.2032)
		(layers "F.Cu" "B.Cu")
		(net "GND")
	)
	(via
		(at 187.883546 -296.766742)
		(size 0.4572)
		(drill 0.2032)
		(layers "F.Cu" "B.Cu")
		(net "GND")
	)
	(via
		(at 208.563972 -34.196528)
		(size 0.508)
		(drill 0.254)
		(layers "F.Cu" "B.Cu")
		(net "GND")
	)
	(via
		(at 3.579368 -72.92721)
		(size 0.508)
		(drill 0.254)
		(layers "F.Cu" "B.Cu")
		(net "GND")
	)
	(via
		(at 462.555082 -282.316682)
		(size 0.4572)
		(drill 0.2032)
		(layers "F.Cu" "B.Cu")
		(net "GND")
	)
	(via
		(at 450.911214 -208.366614)
		(size 0.4572)
		(drill 0.2032)
		(layers "F.Cu" "B.Cu")
		(net "GND")
	)
	(via
		(at 272.273014 -317.166752)
		(size 0.4572)
		(drill 0.2032)
		(layers "F.Cu" "B.Cu")
		(net "GND")
	)
	(via
		(at 268.829282 -198.166736)
		(size 0.4572)
		(drill 0.2032)
		(layers "F.Cu" "B.Cu")
		(net "GND")
	)
	(via
		(at 35.976814 -286.56661)
		(size 0.4572)
		(drill 0.2032)
		(layers "F.Cu" "B.Cu")
		(net "GND")
	)
	(via
		(at 83.991196 -93.538294)
		(size 0.508)
		(drill 0.254)
		(layers "F.Cu" "B.Cu")
		(net "GND")
	)
	(via
		(at 297.833288 -362.414566)
		(size 0.49022)
		(drill 0.254)
		(layers "F.Cu" "B.Cu")
		(net "GND")
	)
	(via
		(at 92.844366 -227.64496)
		(size 0.4572)
		(drill 0.2032)
		(layers "F.Cu" "B.Cu")
		(net "GND")
	)
	(via
		(at 187.758324 -153.178256)
		(size 0.508)
		(drill 0.254)
		(layers "F.Cu" "B.Cu")
		(net "GND")
	)
	(via
		(at 428.279814 -227.066602)
		(size 0.4572)
		(drill 0.2032)
		(layers "F.Cu" "B.Cu")
		(net "GND")
	)
	(via
		(at 165.252146 -203.266802)
		(size 0.4572)
		(drill 0.2032)
		(layers "F.Cu" "B.Cu")
		(net "GND")
	)
	(via
		(at 171.562014 -244.066568)
		(size 0.4572)
		(drill 0.2032)
		(layers "F.Cu" "B.Cu")
		(net "GND")
	)
	(via
		(at 368.50828 -228.45903)
		(size 0.4572)
		(drill 0.2032)
		(layers "F.Cu" "B.Cu")
		(net "GND")
	)
	(via
		(at 165.252146 -301.866808)
		(size 0.4572)
		(drill 0.2032)
		(layers "F.Cu" "B.Cu")
		(net "GND")
	)
	(via
		(at 58.608214 -224.516696)
		(size 0.4572)
		(drill 0.2032)
		(layers "F.Cu" "B.Cu")
		(net "GND")
	)
	(via
		(at 112.110266 -236.597698)
		(size 0.4572)
		(drill 0.2032)
		(layers "F.Cu" "B.Cu")
		(net "GND")
	)
	(via
		(at 207.071214 -269.566644)
		(size 0.4572)
		(drill 0.2032)
		(layers "F.Cu" "B.Cu")
		(net "GND")
	)
	(via
		(at 340.894416 -271.825212)
		(size 0.4572)
		(drill 0.2032)
		(layers "F.Cu" "B.Cu")
		(net "GND")
	)
	(via
		(at 135.176514 -410.030168)
		(size 0.4064)
		(drill 0.2032)
		(layers "F.Cu" "B.Cu")
		(net "GND")
	)
	(via
		(at 139.364466 -231.714548)
		(size 0.4572)
		(drill 0.2032)
		(layers "F.Cu" "B.Cu")
		(net "GND")
	)
	(via
		(at 29.666946 -217.716608)
		(size 0.4572)
		(drill 0.2032)
		(layers "F.Cu" "B.Cu")
		(net "GND")
	)
	(via
		(at 413.192214 -231.316784)
		(size 0.4572)
		(drill 0.2032)
		(layers "F.Cu" "B.Cu")
		(net "GND")
	)
	(via
		(at 355.821234 -219.506038)
		(size 0.4572)
		(drill 0.2032)
		(layers "F.Cu" "B.Cu")
		(net "GND")
	)
	(via
		(at 54.724046 -311.216802)
		(size 0.4572)
		(drill 0.2032)
		(layers "F.Cu" "B.Cu")
		(net "GND")
	)
	(via
		(at 101.412548 -266.941808)
		(size 0.4572)
		(drill 0.2032)
		(layers "F.Cu" "B.Cu")
		(net "GND")
	)
	(via
		(at 447.467482 -213.46668)
		(size 0.4572)
		(drill 0.2032)
		(layers "F.Cu" "B.Cu")
		(net "GND")
	)
	(via
		(at 279.816814 -234.716574)
		(size 0.4572)
		(drill 0.2032)
		(layers "F.Cu" "B.Cu")
		(net "GND")
	)
	(via
		(at 61.212222 -151.59228)
		(size 0.508)
		(drill 0.254)
		(layers "F.Cu" "B.Cu")
		(net "GND")
	)
	(via
		(at 385.726432 -12.541758)
		(size 0.508)
		(drill 0.254)
		(layers "F.Cu" "B.Cu")
		(net "GND")
	)
	(via
		(at 462.555082 -228.766624)
		(size 0.4572)
		(drill 0.2032)
		(layers "F.Cu" "B.Cu")
		(net "GND")
	)
	(via
		(at 116.762784 -295.03878)
		(size 0.508)
		(drill 0.254)
		(layers "F.Cu" "B.Cu")
		(net "GND")
	)
	(via
		(at 46.964346 -279.766776)
		(size 0.4572)
		(drill 0.2032)
		(layers "F.Cu" "B.Cu")
		(net "GND")
	)
	(via
		(at 180.339746 -197.316598)
		(size 0.4572)
		(drill 0.2032)
		(layers "F.Cu" "B.Cu")
		(net "GND")
	)
	(via
		(at 272.273014 -251.716794)
		(size 0.4572)
		(drill 0.2032)
		(layers "F.Cu" "B.Cu")
		(net "GND")
	)
	(via
		(at 450.911214 -261.916672)
		(size 0.4572)
		(drill 0.2032)
		(layers "F.Cu" "B.Cu")
		(net "GND")
	)
	(via
		(at 276.373082 -272.966688)
		(size 0.4572)
		(drill 0.2032)
		(layers "F.Cu" "B.Cu")
		(net "GND")
	)
	(via
		(at 294.904414 -304.416714)
		(size 0.4572)
		(drill 0.2032)
		(layers "F.Cu" "B.Cu")
		(net "GND")
	)
	(via
		(at 113.629948 -255.547876)
		(size 0.4572)
		(drill 0.2032)
		(layers "F.Cu" "B.Cu")
		(net "GND")
	)
	(via
		(at 16.789146 -204.96657)
		(size 0.4572)
		(drill 0.2032)
		(layers "F.Cu" "B.Cu")
		(net "GND")
	)
	(via
		(at 14.579346 -279.766776)
		(size 0.4572)
		(drill 0.2032)
		(layers "F.Cu" "B.Cu")
		(net "GND")
	)
	(via
		(at 306.548282 -230.466646)
		(size 0.4572)
		(drill 0.2032)
		(layers "F.Cu" "B.Cu")
		(net "GND")
	)
	(via
		(at 44.840906 -16.978376)
		(size 0.508)
		(drill 0.254)
		(layers "F.Cu" "B.Cu")
		(net "GND")
	)
	(via
		(at 35.976814 -267.866622)
		(size 0.4572)
		(drill 0.2032)
		(layers "F.Cu" "B.Cu")
		(net "GND")
	)
	(via
		(at 300.238414 -212.616796)
		(size 0.4572)
		(drill 0.2032)
		(layers "F.Cu" "B.Cu")
		(net "GND")
	)
	(via
		(at 443.367414 -272.116804)
		(size 0.4572)
		(drill 0.2032)
		(layers "F.Cu" "B.Cu")
		(net "GND")
	)
	(via
		(at 78.500732 -0.76454)
		(size 0.508)
		(drill 0.254)
		(layers "F.Cu" "B.Cu")
		(net "GND")
	)
	(via
		(at 417.98875 -151.83993)
		(size 0.508)
		(drill 0.254)
		(layers "F.Cu" "B.Cu")
		(net "GND")
	)
	(via
		(at 161.808414 -211.766658)
		(size 0.4572)
		(drill 0.2032)
		(layers "F.Cu" "B.Cu")
		(net "GND")
	)
	(via
		(at 26.223214 -282.316682)
		(size 0.4572)
		(drill 0.2032)
		(layers "F.Cu" "B.Cu")
		(net "GND")
	)
	(via
		(at 326.37222 -31.730188)
		(size 0.49022)
		(drill 0.254)
		(layers "F.Cu" "B.Cu")
		(net "GND")
	)
	(via
		(at 281.707082 -216.866724)
		(size 0.4572)
		(drill 0.2032)
		(layers "F.Cu" "B.Cu")
		(net "GND")
	)
	(via
		(at 403.349968 -430.299622)
		(size 0.4572)
		(drill 0.2032)
		(layers "F.Cu" "B.Cu")
		(net "GND")
	)
	(via
		(at 343.243408 -403.883876)
		(size 0.4064)
		(drill 0.2032)
		(layers "F.Cu" "B.Cu")
		(net "GND")
	)
	(via
		(at 342.735154 -53.618892)
		(size 0.4572)
		(drill 0.2032)
		(layers "F.Cu" "B.Cu")
		(net "GND")
	)
	(via
		(at 130.906266 -226.831144)
		(size 0.4572)
		(drill 0.2032)
		(layers "F.Cu" "B.Cu")
		(net "GND")
	)
	(via
		(at 334.76438 -335.187036)
		(size 0.49022)
		(drill 0.254)
		(layers "F.Cu" "B.Cu")
		(net "GND")
	)
	(via
		(at 58.318146 -409.396184)
		(size 0.4572)
		(drill 0.254)
		(layers "F.Cu" "B.Cu")
		(net "GND")
	)
	(via
		(at 119.738394 -282.405836)
		(size 0.4572)
		(drill 0.2032)
		(layers "F.Cu" "B.Cu")
		(net "GND")
	)
	(via
		(at 270.063214 -248.31675)
		(size 0.4572)
		(drill 0.2032)
		(layers "F.Cu" "B.Cu")
		(net "GND")
	)
	(via
		(at 165.077902 -311.216802)
		(size 0.4572)
		(drill 0.2032)
		(layers "F.Cu" "B.Cu")
		(net "GND")
	)
	(via
		(at 18.76171 -193.843656)
		(size 0.508)
		(drill 0.254)
		(layers "F.Cu" "B.Cu")
		(net "GND")
	)
	(via
		(at 59.842146 -240.666778)
		(size 0.4572)
		(drill 0.2032)
		(layers "F.Cu" "B.Cu")
		(net "GND")
	)
	(via
		(at 216.824814 -210.066636)
		(size 0.4572)
		(drill 0.2032)
		(layers "F.Cu" "B.Cu")
		(net "GND")
	)
	(via
		(at 132.425948 -281.59202)
		(size 0.4572)
		(drill 0.2032)
		(layers "F.Cu" "B.Cu")
		(net "GND")
	)
	(via
		(at 199.527414 -289.966654)
		(size 0.4572)
		(drill 0.2032)
		(layers "F.Cu" "B.Cu")
		(net "GND")
	)
	(via
		(at 82.56397 -60.253626)
		(size 0.508)
		(drill 0.254)
		(layers "F.Cu" "B.Cu")
		(net "GND")
	)
	(via
		(at 375.557034 -216.25052)
		(size 0.4572)
		(drill 0.2032)
		(layers "F.Cu" "B.Cu")
		(net "GND")
	)
	(via
		(at 342.773762 -286.475424)
		(size 0.4572)
		(drill 0.2032)
		(layers "F.Cu" "B.Cu")
		(net "GND")
	)
	(via
		(at 420.736014 -278.066754)
		(size 0.4572)
		(drill 0.2032)
		(layers "F.Cu" "B.Cu")
		(net "GND")
	)
	(via
		(at 326.080374 -39.570152)
		(size 0.49022)
		(drill 0.254)
		(layers "F.Cu" "B.Cu")
		(net "GND")
	)
	(via
		(at 395.63421 -407.00452)
		(size 0.4064)
		(drill 0.2032)
		(layers "F.Cu" "B.Cu")
		(net "GND")
	)
	(via
		(at 351.59188 -334.282034)
		(size 0.49022)
		(drill 0.254)
		(layers "F.Cu" "B.Cu")
		(net "GND")
	)
	(via
		(at 87.675466 -223.575626)
		(size 0.4572)
		(drill 0.2032)
		(layers "F.Cu" "B.Cu")
		(net "GND")
	)
	(via
		(at 203.7588 -91.5924)
		(size 0.508)
		(drill 0.254)
		(layers "F.Cu" "B.Cu")
		(net "GND")
	)
	(via
		(at 350.846898 -240.344706)
		(size 0.4572)
		(drill 0.2032)
		(layers "F.Cu" "B.Cu")
		(net "GND")
	)
	(via
		(at 99.063048 -257.98907)
		(size 0.4572)
		(drill 0.2032)
		(layers "F.Cu" "B.Cu")
		(net "GND")
	)
	(via
		(at 58.608214 -215.166702)
		(size 0.4572)
		(drill 0.2032)
		(layers "F.Cu" "B.Cu")
		(net "GND")
	)
	(via
		(at 124.907294 -255.547622)
		(size 0.4572)
		(drill 0.2032)
		(layers "F.Cu" "B.Cu")
		(net "GND")
	)
	(via
		(at 259.075682 -221.116652)
		(size 0.4572)
		(drill 0.2032)
		(layers "F.Cu" "B.Cu")
		(net "GND")
	)
	(via
		(at 430.489614 -296.766742)
		(size 0.4572)
		(drill 0.2032)
		(layers "F.Cu" "B.Cu")
		(net "GND")
	)
	(via
		(at 272.340832 -439.905394)
		(size 0.508)
		(drill 0.254)
		(layers "F.Cu" "B.Cu")
		(net "GND")
	)
	(via
		(at 257.185414 -197.316598)
		(size 0.4572)
		(drill 0.2032)
		(layers "F.Cu" "B.Cu")
		(net "GND")
	)
	(via
		(at 81.116678 -400.858228)
		(size 0.4064)
		(drill 0.2032)
		(layers "F.Cu" "B.Cu")
		(net "GND")
	)
	(via
		(at 51.064414 -305.266598)
		(size 0.4572)
		(drill 0.2032)
		(layers "F.Cu" "B.Cu")
		(net "GND")
	)
	(via
		(at 129.032 -60.416948)
		(size 0.508)
		(drill 0.254)
		(layers "F.Cu" "B.Cu")
		(net "GND")
	)
	(via
		(at 26.223214 -294.216582)
		(size 0.4572)
		(drill 0.2032)
		(layers "F.Cu" "B.Cu")
		(net "GND")
	)
	(via
		(at 91.074494 -278.336502)
		(size 0.4572)
		(drill 0.2032)
		(layers "F.Cu" "B.Cu")
		(net "GND")
	)
	(via
		(at 219.10548 -126.761748)
		(size 0.508)
		(drill 0.254)
		(layers "F.Cu" "B.Cu")
		(net "GND")
	)
	(via
		(at 81.01965 -410.664152)
		(size 0.4572)
		(drill 0.254)
		(layers "F.Cu" "B.Cu")
		(net "GND")
	)
	(via
		(at 439.923682 -280.61666)
		(size 0.4572)
		(drill 0.2032)
		(layers "F.Cu" "B.Cu")
		(net "GND")
	)
	(via
		(at 14.426946 -395.247876)
		(size 0.508)
		(drill 0.254)
		(layers "F.Cu" "B.Cu")
		(net "GND")
	)
	(via
		(at 352.85172 -335.704434)
		(size 0.49022)
		(drill 0.254)
		(layers "F.Cu" "B.Cu")
		(net "GND")
	)
	(via
		(at 442.133482 -196.466714)
		(size 0.4572)
		(drill 0.2032)
		(layers "F.Cu" "B.Cu")
		(net "GND")
	)
	(via
		(at 212.724746 -234.716574)
		(size 0.4572)
		(drill 0.2032)
		(layers "F.Cu" "B.Cu")
		(net "GND")
	)
	(via
		(at 154.911806 -404.51786)
		(size 0.4572)
		(drill 0.254)
		(layers "F.Cu" "B.Cu")
		(net "GND")
	)
	(via
		(at 181.302914 -413.973264)
		(size 0.508)
		(drill 0.254)
		(layers "F.Cu" "B.Cu")
		(net "GND")
	)
	(via
		(at 328.647298 -347.990922)
		(size 0.508)
		(drill 0.254)
		(layers "F.Cu" "B.Cu")
		(net "GND")
	)
	(via
		(at 202.971146 -212.616796)
		(size 0.4572)
		(drill 0.2032)
		(layers "F.Cu" "B.Cu")
		(net "GND")
	)
	(via
		(at 48.854614 -249.166634)
		(size 0.4572)
		(drill 0.2032)
		(layers "F.Cu" "B.Cu")
		(net "GND")
	)
	(via
		(at 201.737214 -291.666676)
		(size 0.4572)
		(drill 0.2032)
		(layers "F.Cu" "B.Cu")
		(net "GND")
	)
	(via
		(at 79.760826 -407.638504)
		(size 0.4572)
		(drill 0.254)
		(layers "F.Cu" "B.Cu")
		(net "GND")
	)
	(via
		(at 371.907816 -281.59202)
		(size 0.4572)
		(drill 0.2032)
		(layers "F.Cu" "B.Cu")
		(net "GND")
	)
	(via
		(at 86.250018 -426.54728)
		(size 0.4572)
		(drill 0.2032)
		(layers "F.Cu" "B.Cu")
		(net "GND")
	)
	(via
		(at 54.508146 -227.066602)
		(size 0.4572)
		(drill 0.2032)
		(layers "F.Cu" "B.Cu")
		(net "GND")
	)
	(via
		(at 118.433088 -250.33732)
		(size 0.4572)
		(drill 0.2032)
		(layers "F.Cu" "B.Cu")
		(net "GND")
	)
	(via
		(at 254.975614 -216.016586)
		(size 0.4572)
		(drill 0.2032)
		(layers "F.Cu" "B.Cu")
		(net "GND")
	)
	(via
		(at 44.754546 -242.3668)
		(size 0.4572)
		(drill 0.2032)
		(layers "F.Cu" "B.Cu")
		(net "GND")
	)
	(via
		(at 349.946468 -63.594488)
		(size 0.508)
		(drill 0.254)
		(layers "F.Cu" "B.Cu")
		(net "GND")
	)
	(via
		(at 274.163282 -213.46668)
		(size 0.4572)
		(drill 0.2032)
		(layers "F.Cu" "B.Cu")
		(net "GND")
	)
	(via
		(at 274.163282 -312.91657)
		(size 0.4572)
		(drill 0.2032)
		(layers "F.Cu" "B.Cu")
		(net "GND")
	)
	(via
		(at 195.427346 -246.616728)
		(size 0.4572)
		(drill 0.2032)
		(layers "F.Cu" "B.Cu")
		(net "GND")
	)
	(via
		(at 81.455514 -153.021792)
		(size 0.508)
		(drill 0.254)
		(layers "F.Cu" "B.Cu")
		(net "GND")
	)
	(via
		(at 442.133482 -301.01667)
		(size 0.4572)
		(drill 0.2032)
		(layers "F.Cu" "B.Cu")
		(net "GND")
	)
	(via
		(at 131.752086 -409.396184)
		(size 0.4572)
		(drill 0.254)
		(layers "F.Cu" "B.Cu")
		(net "GND")
	)
	(via
		(at 394.404596 -19.125438)
		(size 0.508)
		(drill 0.254)
		(layers "F.Cu" "B.Cu")
		(net "GND")
	)
	(via
		(at 181.80812 -410.10586)
		(size 0.508)
		(drill 0.254)
		(layers "F.Cu" "B.Cu")
		(net "GND")
	)
	(via
		(at 427.045882 -266.1666)
		(size 0.4572)
		(drill 0.2032)
		(layers "F.Cu" "B.Cu")
		(net "GND")
	)
	(via
		(at 259.075682 -282.316682)
		(size 0.4572)
		(drill 0.2032)
		(layers "F.Cu" "B.Cu")
		(net "GND")
	)
	(via
		(at 296.794682 -277.216616)
		(size 0.4572)
		(drill 0.2032)
		(layers "F.Cu" "B.Cu")
		(net "GND")
	)
	(via
		(at 296.794682 -244.066568)
		(size 0.4572)
		(drill 0.2032)
		(layers "F.Cu" "B.Cu")
		(net "GND")
	)
	(via
		(at 96.029526 -326.788272)
		(size 0.508)
		(drill 0.254)
		(layers "F.Cu" "B.Cu")
		(net "GND")
	)
	(via
		(at 263.26592 -151.453088)
		(size 0.508)
		(drill 0.254)
		(layers "F.Cu" "B.Cu")
		(net "GND")
	)
	(via
		(at 60.035186 -401.492212)
		(size 0.4572)
		(drill 0.254)
		(layers "F.Cu" "B.Cu")
		(net "GND")
	)
	(via
		(at 281.707082 -247.466612)
		(size 0.4572)
		(drill 0.2032)
		(layers "F.Cu" "B.Cu")
		(net "GND")
	)
	(via
		(at 268.829282 -239.81664)
		(size 0.4572)
		(drill 0.2032)
		(layers "F.Cu" "B.Cu")
		(net "GND")
	)
	(via
		(at 71.926958 -403.883876)
		(size 0.4064)
		(drill 0.2032)
		(layers "F.Cu" "B.Cu")
		(net "GND")
	)
	(via
		(at 370.967762 -268.569694)
		(size 0.4572)
		(drill 0.2032)
		(layers "F.Cu" "B.Cu")
		(net "GND")
	)
	(via
		(at 22.123146 -285.716726)
		(size 0.4572)
		(drill 0.2032)
		(layers "F.Cu" "B.Cu")
		(net "GND")
	)
	(via
		(at 343.243662 -277.522432)
		(size 0.4572)
		(drill 0.2032)
		(layers "F.Cu" "B.Cu")
		(net "GND")
	)
	(via
		(at 26.223214 -238.116618)
		(size 0.4572)
		(drill 0.2032)
		(layers "F.Cu" "B.Cu")
		(net "GND")
	)
	(via
		(at 209.281014 -288.266632)
		(size 0.4572)
		(drill 0.2032)
		(layers "F.Cu" "B.Cu")
		(net "GND")
	)
	(via
		(at 449.677282 -291.666676)
		(size 0.4572)
		(drill 0.2032)
		(layers "F.Cu" "B.Cu")
		(net "GND")
	)
	(via
		(at 56.398414 -310.366664)
		(size 0.4572)
		(drill 0.2032)
		(layers "F.Cu" "B.Cu")
		(net "GND")
	)
	(via
		(at 335.725262 -254.733552)
		(size 0.4572)
		(drill 0.2032)
		(layers "F.Cu" "B.Cu")
		(net "GND")
	)
	(via
		(at 23.715726 -4.962652)
		(size 0.508)
		(drill 0.254)
		(layers "F.Cu" "B.Cu")
		(net "GND")
	)
	(via
		(at 71.250048 -430.299622)
		(size 0.4572)
		(drill 0.2032)
		(layers "F.Cu" "B.Cu")
		(net "GND")
	)
	(via
		(at 418.488368 -354.182172)
		(size 0.508)
		(drill 0.254)
		(layers "F.Cu" "B.Cu")
		(net "GND")
	)
	(via
		(at 214.615014 -221.116652)
		(size 0.4572)
		(drill 0.2032)
		(layers "F.Cu" "B.Cu")
		(net "GND")
	)
	(via
		(at 69.127878 -410.030168)
		(size 0.4064)
		(drill 0.2032)
		(layers "F.Cu" "B.Cu")
		(net "GND")
	)
	(via
		(at 32.30753 -429.859948)
		(size 0.508)
		(drill 0.254)
		(layers "F.Cu" "B.Cu")
		(net "GND")
	)
	(via
		(at 428.279814 -244.916706)
		(size 0.4572)
		(drill 0.2032)
		(layers "F.Cu" "B.Cu")
		(net "GND")
	)
	(via
		(at 358.280462 -271.011396)
		(size 0.4572)
		(drill 0.2032)
		(layers "F.Cu" "B.Cu")
		(net "GND")
	)
	(via
		(at 399.484596 -18.491454)
		(size 0.508)
		(drill 0.254)
		(layers "F.Cu" "B.Cu")
		(net "GND")
	)
	(via
		(at 323.250052 -436.347362)
		(size 0.4572)
		(drill 0.2032)
		(layers "F.Cu" "B.Cu")
		(net "GND")
	)
	(via
		(at 112.110266 -234.970066)
		(size 0.4572)
		(drill 0.2032)
		(layers "F.Cu" "B.Cu")
		(net "GND")
	)
	(via
		(at 185.43778 -128.577848)
		(size 0.508)
		(drill 0.254)
		(layers "F.Cu" "B.Cu")
		(net "GND")
	)
	(via
		(at 100.362766 -222.761556)
		(size 0.4572)
		(drill 0.2032)
		(layers "F.Cu" "B.Cu")
		(net "GND")
	)
	(via
		(at 396.349982 -428.851314)
		(size 0.4572)
		(drill 0.2032)
		(layers "F.Cu" "B.Cu")
		(net "GND")
	)
	(via
		(at 207.071214 -280.61666)
		(size 0.4572)
		(drill 0.2032)
		(layers "F.Cu" "B.Cu")
		(net "GND")
	)
	(via
		(at 233.853228 -125.624844)
		(size 0.508)
		(drill 0.254)
		(layers "F.Cu" "B.Cu")
		(net "GND")
	)
	(via
		(at 20.346924 -10.16508)
		(size 0.508)
		(drill 0.254)
		(layers "F.Cu" "B.Cu")
		(net "GND")
	)
	(via
		(at 129.136394 -279.150318)
		(size 0.4572)
		(drill 0.2032)
		(layers "F.Cu" "B.Cu")
		(net "GND")
	)
	(via
		(at 126.964186 -353.828858)
		(size 0.508)
		(drill 0.254)
		(layers "F.Cu" "B.Cu")
		(net "GND")
	)
	(via
		(at 337.49488 -236.597952)
		(size 0.4572)
		(drill 0.2032)
		(layers "F.Cu" "B.Cu")
		(net "GND")
	)
	(via
		(at 130.405886 -404.51786)
		(size 0.4572)
		(drill 0.254)
		(layers "F.Cu" "B.Cu")
		(net "GND")
	)
	(via
		(at 43.520614 -219.41663)
		(size 0.4572)
		(drill 0.2032)
		(layers "F.Cu" "B.Cu")
		(net "GND")
	)
	(via
		(at 337.604862 -277.522432)
		(size 0.4572)
		(drill 0.2032)
		(layers "F.Cu" "B.Cu")
		(net "GND")
	)
	(via
		(at 262.519414 -301.866808)
		(size 0.4572)
		(drill 0.2032)
		(layers "F.Cu" "B.Cu")
		(net "GND")
	)
	(via
		(at 172.795946 -223.666558)
		(size 0.4572)
		(drill 0.2032)
		(layers "F.Cu" "B.Cu")
		(net "GND")
	)
	(via
		(at 289.414966 -360.83621)
		(size 0.49022)
		(drill 0.254)
		(layers "F.Cu" "B.Cu")
		(net "GND")
	)
	(via
		(at 318.64046 -410.664152)
		(size 0.4572)
		(drill 0.254)
		(layers "F.Cu" "B.Cu")
		(net "GND")
	)
	(via
		(at 378.84608 -241.481102)
		(size 0.4572)
		(drill 0.2032)
		(layers "F.Cu" "B.Cu")
		(net "GND")
	)
	(via
		(at 182.549546 -296.766742)
		(size 0.4572)
		(drill 0.2032)
		(layers "F.Cu" "B.Cu")
		(net "GND")
	)
	(via
		(at 427.045882 -247.466612)
		(size 0.4572)
		(drill 0.2032)
		(layers "F.Cu" "B.Cu")
		(net "GND")
	)
	(via
		(at 341.288624 -84.010246)
		(size 0.508)
		(drill 0.254)
		(layers "F.Cu" "B.Cu")
		(net "GND")
	)
	(via
		(at 138.382502 -335.957672)
		(size 0.508)
		(drill 0.254)
		(layers "F.Cu" "B.Cu")
		(net "GND")
	)
	(via
		(at 124.437394 -266.128246)
		(size 0.4572)
		(drill 0.2032)
		(layers "F.Cu" "B.Cu")
		(net "GND")
	)
	(via
		(at 367.483644 -409.102306)
		(size 0.508)
		(drill 0.254)
		(layers "F.Cu" "B.Cu")
		(net "GND")
	)
	(via
		(at 236.06252 -388.01294)
		(size 0.508)
		(drill 0.254)
		(layers "F.Cu" "B.Cu")
		(net "GND")
	)
	(via
		(at 458.455014 -203.266802)
		(size 0.4572)
		(drill 0.2032)
		(layers "F.Cu" "B.Cu")
		(net "GND")
	)
	(via
		(at 382.245616 -265.314176)
		(size 0.4572)
		(drill 0.2032)
		(layers "F.Cu" "B.Cu")
		(net "GND")
	)
	(via
		(at 26.223214 -297.616626)
		(size 0.4572)
		(drill 0.2032)
		(layers "F.Cu" "B.Cu")
		(net "GND")
	)
	(via
		(at 205.180946 -272.116804)
		(size 0.4572)
		(drill 0.2032)
		(layers "F.Cu" "B.Cu")
		(net "GND")
	)
	(via
		(at 443.367414 -313.766708)
		(size 0.4572)
		(drill 0.2032)
		(layers "F.Cu" "B.Cu")
		(net "GND")
	)
	(via
		(at 326.210168 -407.00452)
		(size 0.4064)
		(drill 0.2032)
		(layers "F.Cu" "B.Cu")
		(net "GND")
	)
	(via
		(at 442.133482 -305.266598)
		(size 0.4572)
		(drill 0.2032)
		(layers "F.Cu" "B.Cu")
		(net "GND")
	)
	(via
		(at 107.500166 -326.836532)
		(size 0.508)
		(drill 0.254)
		(layers "F.Cu" "B.Cu")
		(net "GND")
	)
	(via
		(at 40.614092 -345.64066)
		(size 0.508)
		(drill 0.254)
		(layers "F.Cu" "B.Cu")
		(net "GND")
	)
	(via
		(at 49.666906 -9.424924)
		(size 0.508)
		(drill 0.254)
		(layers "F.Cu" "B.Cu")
		(net "GND")
	)
	(via
		(at 191.983614 -194.766692)
		(size 0.4572)
		(drill 0.2032)
		(layers "F.Cu" "B.Cu")
		(net "GND")
	)
	(via
		(at 89.664794 -279.150318)
		(size 0.4572)
		(drill 0.2032)
		(layers "F.Cu" "B.Cu")
		(net "GND")
	)
	(via
		(at 160.121346 -236.397038)
		(size 0.4572)
		(drill 0.2032)
		(layers "F.Cu" "B.Cu")
		(net "GND")
	)
	(via
		(at 180.339746 -265.316716)
		(size 0.4572)
		(drill 0.2032)
		(layers "F.Cu" "B.Cu")
		(net "GND")
	)
	(via
		(at 178.75377 -327.79843)
		(size 0.508)
		(drill 0.254)
		(layers "F.Cu" "B.Cu")
		(net "GND")
	)
	(via
		(at 438.033414 -201.56678)
		(size 0.4572)
		(drill 0.2032)
		(layers "F.Cu" "B.Cu")
		(net "GND")
	)
	(via
		(at 383.655062 -254.733552)
		(size 0.4572)
		(drill 0.2032)
		(layers "F.Cu" "B.Cu")
		(net "GND")
	)
	(via
		(at 21.63191 -181.456076)
		(size 0.508)
		(drill 0.254)
		(layers "F.Cu" "B.Cu")
		(net "GND")
	)
	(via
		(at 171.332398 -351.614994)
		(size 0.49022)
		(drill 0.254)
		(layers "F.Cu" "B.Cu")
		(net "GND")
	)
	(via
		(at 19.417284 -323.434456)
		(size 0.4572)
		(drill 0.2032)
		(layers "F.Cu" "B.Cu")
		(net "GND")
	)
	(via
		(at 48.854614 -264.466578)
		(size 0.4572)
		(drill 0.2032)
		(layers "F.Cu" "B.Cu")
		(net "GND")
	)
	(via
		(at 7.035546 -278.066754)
		(size 0.4572)
		(drill 0.2032)
		(layers "F.Cu" "B.Cu")
		(net "GND")
	)
	(via
		(at 405.648414 -197.316598)
		(size 0.4572)
		(drill 0.2032)
		(layers "F.Cu" "B.Cu")
		(net "GND")
	)
	(via
		(at 13.345414 -219.41663)
		(size 0.4572)
		(drill 0.2032)
		(layers "F.Cu" "B.Cu")
		(net "GND")
	)
	(via
		(at 72.662034 -12.37488)
		(size 0.508)
		(drill 0.254)
		(layers "F.Cu" "B.Cu")
		(net "GND")
	)
	(via
		(at 375.547382 -403.249892)
		(size 0.4572)
		(drill 0.254)
		(layers "F.Cu" "B.Cu")
		(net "GND")
	)
	(via
		(at 417.07689 -406.980644)
		(size 0.4064)
		(drill 0.2032)
		(layers "F.Cu" "B.Cu")
		(net "GND")
	)
	(via
		(at 366.738662 -282.405836)
		(size 0.4572)
		(drill 0.2032)
		(layers "F.Cu" "B.Cu")
		(net "GND")
	)
	(via
		(at 300.022514 -208.366614)
		(size 0.4572)
		(drill 0.2032)
		(layers "F.Cu" "B.Cu")
		(net "GND")
	)
	(via
		(at 20.889214 -303.566576)
		(size 0.4572)
		(drill 0.2032)
		(layers "F.Cu" "B.Cu")
		(net "GND")
	)
	(via
		(at 176.896014 -205.816708)
		(size 0.4572)
		(drill 0.2032)
		(layers "F.Cu" "B.Cu")
		(net "GND")
	)
	(via
		(at 77.95641 -407.638504)
		(size 0.4572)
		(drill 0.254)
		(layers "F.Cu" "B.Cu")
		(net "GND")
	)
	(via
		(at 299.700188 -387.147562)
		(size 0.508)
		(drill 0.254)
		(layers "F.Cu" "B.Cu")
		(net "GND")
	)
	(via
		(at 161.58718 -238.116618)
		(size 0.4572)
		(drill 0.2032)
		(layers "F.Cu" "B.Cu")
		(net "GND")
	)
	(via
		(at 70.861936 -12.37488)
		(size 0.508)
		(drill 0.254)
		(layers "F.Cu" "B.Cu")
		(net "GND")
	)
	(via
		(at 447.467482 -245.76659)
		(size 0.4572)
		(drill 0.2032)
		(layers "F.Cu" "B.Cu")
		(net "GND")
	)
	(via
		(at 420.156894 -10.16508)
		(size 0.508)
		(drill 0.254)
		(layers "F.Cu" "B.Cu")
		(net "GND")
	)
	(via
		(at 412.160974 -312.91657)
		(size 0.4572)
		(drill 0.2032)
		(layers "F.Cu" "B.Cu")
		(net "GND")
	)
	(via
		(at 355.28758 -331.780896)
		(size 0.49022)
		(drill 0.254)
		(layers "F.Cu" "B.Cu")
		(net "GND")
	)
	(via
		(at 56.398414 -233.86669)
		(size 0.4572)
		(drill 0.2032)
		(layers "F.Cu" "B.Cu")
		(net "GND")
	)
	(via
		(at 424.836082 -258.516628)
		(size 0.4572)
		(drill 0.2032)
		(layers "F.Cu" "B.Cu")
		(net "GND")
	)
	(via
		(at 347.363034 -229.272846)
		(size 0.4572)
		(drill 0.2032)
		(layers "F.Cu" "B.Cu")
		(net "GND")
	)
	(via
		(at 164.101526 -401.492212)
		(size 0.4572)
		(drill 0.254)
		(layers "F.Cu" "B.Cu")
		(net "GND")
	)
	(via
		(at 23.060152 -407.890218)
		(size 0.508)
		(drill 0.254)
		(layers "F.Cu" "B.Cu")
		(net "GND")
	)
	(via
		(at 334.414876 -401.492212)
		(size 0.4572)
		(drill 0.254)
		(layers "F.Cu" "B.Cu")
		(net "GND")
	)
	(via
		(at 262.519414 -227.066602)
		(size 0.4572)
		(drill 0.2032)
		(layers "F.Cu" "B.Cu")
		(net "GND")
	)
	(via
		(at 430.97704 -124.512578)
		(size 0.508)
		(drill 0.254)
		(layers "F.Cu" "B.Cu")
		(net "GND")
	)
	(via
		(at 80.066134 -348.60103)
		(size 0.508)
		(drill 0.254)
		(layers "F.Cu" "B.Cu")
		(net "GND")
	)
	(via
		(at 349.352616 -271.825212)
		(size 0.4572)
		(drill 0.2032)
		(layers "F.Cu" "B.Cu")
		(net "GND")
	)
	(via
		(at 88.145112 -214.622634)
		(size 0.4572)
		(drill 0.2032)
		(layers "F.Cu" "B.Cu")
		(net "GND")
	)
	(via
		(at 135.273542 -403.249892)
		(size 0.4572)
		(drill 0.254)
		(layers "F.Cu" "B.Cu")
		(net "GND")
	)
	(via
		(at 238.530638 -133.923278)
		(size 0.508)
		(drill 0.254)
		(layers "F.Cu" "B.Cu")
		(net "GND")
	)
	(via
		(at 61.250068 -431.29962)
		(size 0.4572)
		(drill 0.2032)
		(layers "F.Cu" "B.Cu")
		(net "GND")
	)
	(via
		(at 40.691054 -355.531928)
		(size 0.49022)
		(drill 0.254)
		(layers "F.Cu" "B.Cu")
		(net "GND")
	)
	(via
		(at 157.573726 -285.742126)
		(size 0.4572)
		(drill 0.2032)
		(layers "F.Cu" "B.Cu")
		(net "GND")
	)
	(via
		(at 351.468436 -60.281566)
		(size 0.508)
		(drill 0.254)
		(layers "F.Cu" "B.Cu")
		(net "GND")
	)
	(via
		(at 384.015234 -240.667286)
		(size 0.4572)
		(drill 0.2032)
		(layers "F.Cu" "B.Cu")
		(net "GND")
	)
	(via
		(at 11.135614 -239.81664)
		(size 0.4572)
		(drill 0.2032)
		(layers "F.Cu" "B.Cu")
		(net "GND")
	)
	(via
		(at 415.649918 -177.293778)
		(size 0.49022)
		(drill 0.254)
		(layers "F.Cu" "B.Cu")
		(net "GND")
	)
	(via
		(at 14.579346 -250.016772)
		(size 0.4572)
		(drill 0.2032)
		(layers "F.Cu" "B.Cu")
		(net "GND")
	)
	(via
		(at 126.083822 -404.51786)
		(size 0.4572)
		(drill 0.254)
		(layers "F.Cu" "B.Cu")
		(net "GND")
	)
	(via
		(at 272.273014 -240.666778)
		(size 0.4572)
		(drill 0.2032)
		(layers "F.Cu" "B.Cu")
		(net "GND")
	)
	(via
		(at 389.27786 -57.259728)
		(size 0.508)
		(drill 0.254)
		(layers "F.Cu" "B.Cu")
		(net "GND")
	)
	(via
		(at 255.63449 -43.902122)
		(size 0.508)
		(drill 0.254)
		(layers "F.Cu" "B.Cu")
		(net "GND")
	)
	(via
		(at 373.317262 -280.778204)
		(size 0.4572)
		(drill 0.2032)
		(layers "F.Cu" "B.Cu")
		(net "GND")
	)
	(via
		(at 210.514946 -201.56678)
		(size 0.4572)
		(drill 0.2032)
		(layers "F.Cu" "B.Cu")
		(net "GND")
	)
	(via
		(at 26.223214 -291.666676)
		(size 0.4572)
		(drill 0.2032)
		(layers "F.Cu" "B.Cu")
		(net "GND")
	)
	(via
		(at 332.250034 -431.451258)
		(size 0.4572)
		(drill 0.2032)
		(layers "F.Cu" "B.Cu")
		(net "GND")
	)
	(via
		(at 52.911248 -164.23767)
		(size 0.49022)
		(drill 0.254)
		(layers "F.Cu" "B.Cu")
		(net "GND")
	)
	(via
		(at 376.21337 -352.486468)
		(size 0.508)
		(drill 0.254)
		(layers "F.Cu" "B.Cu")
		(net "GND")
	)
	(via
		(at 191.983614 -310.366664)
		(size 0.4572)
		(drill 0.2032)
		(layers "F.Cu" "B.Cu")
		(net "GND")
	)
	(via
		(at 112.442498 -334.282034)
		(size 0.49022)
		(drill 0.254)
		(layers "F.Cu" "B.Cu")
		(net "GND")
	)
	(via
		(at 268.829282 -247.466612)
		(size 0.4572)
		(drill 0.2032)
		(layers "F.Cu" "B.Cu")
		(net "GND")
	)
	(via
		(at 154.801824 -52.068476)
		(size 0.508)
		(drill 0.254)
		(layers "F.Cu" "B.Cu")
		(net "GND")
	)
	(via
		(at 36.962588 -399.293334)
		(size 0.508)
		(drill 0.254)
		(layers "F.Cu" "B.Cu")
		(net "GND")
	)
	(via
		(at 283.916882 -280.61666)
		(size 0.4572)
		(drill 0.2032)
		(layers "F.Cu" "B.Cu")
		(net "GND")
	)
	(via
		(at 439.923682 -239.81664)
		(size 0.4572)
		(drill 0.2032)
		(layers "F.Cu" "B.Cu")
		(net "GND")
	)
	(via
		(at 182.549546 -263.616694)
		(size 0.4572)
		(drill 0.2032)
		(layers "F.Cu" "B.Cu")
		(net "GND")
	)
	(via
		(at 101.412294 -263.686544)
		(size 0.4572)
		(drill 0.2032)
		(layers "F.Cu" "B.Cu")
		(net "GND")
	)
	(via
		(at 182.82158 -410.10586)
		(size 0.508)
		(drill 0.254)
		(layers "F.Cu" "B.Cu")
		(net "GND")
	)
	(via
		(at 270.063214 -290.816792)
		(size 0.4572)
		(drill 0.2032)
		(layers "F.Cu" "B.Cu")
		(net "GND")
	)
	(via
		(at 44.905422 -402.633942)
		(size 0.508)
		(drill 0.254)
		(layers "F.Cu" "B.Cu")
		(net "GND")
	)
	(via
		(at 443.367414 -203.266802)
		(size 0.4572)
		(drill 0.2032)
		(layers "F.Cu" "B.Cu")
		(net "GND")
	)
	(via
		(at 202.971146 -315.46673)
		(size 0.4572)
		(drill 0.2032)
		(layers "F.Cu" "B.Cu")
		(net "GND")
	)
	(via
		(at 39.420546 -283.166566)
		(size 0.4572)
		(drill 0.2032)
		(layers "F.Cu" "B.Cu")
		(net "GND")
	)
	(via
		(at 444.755524 -68.493894)
		(size 0.508)
		(drill 0.254)
		(layers "F.Cu" "B.Cu")
		(net "GND")
	)
	(via
		(at 380.256034 -216.25052)
		(size 0.4572)
		(drill 0.2032)
		(layers "F.Cu" "B.Cu")
		(net "GND")
	)
	(via
		(at 84.385912 -232.528364)
		(size 0.4572)
		(drill 0.2032)
		(layers "F.Cu" "B.Cu")
		(net "GND")
	)
	(via
		(at 261.285482 -230.466646)
		(size 0.4572)
		(drill 0.2032)
		(layers "F.Cu" "B.Cu")
		(net "GND")
	)
	(via
		(at 50.60188 -187.797948)
		(size 0.508)
		(drill 0.254)
		(layers "F.Cu" "B.Cu")
		(net "GND")
	)
	(via
		(at 257.185414 -315.46673)
		(size 0.4572)
		(drill 0.2032)
		(layers "F.Cu" "B.Cu")
		(net "GND")
	)
	(via
		(at 100.29444 -131.778248)
		(size 0.508)
		(drill 0.254)
		(layers "F.Cu" "B.Cu")
		(net "GND")
	)
	(via
		(at 164.183822 -235.591604)
		(size 0.4572)
		(drill 0.2032)
		(layers "F.Cu" "B.Cu")
		(net "GND")
	)
	(via
		(at 212.724746 -317.166752)
		(size 0.4572)
		(drill 0.2032)
		(layers "F.Cu" "B.Cu")
		(net "GND")
	)
	(via
		(at 306.548282 -241.516662)
		(size 0.4572)
		(drill 0.2032)
		(layers "F.Cu" "B.Cu")
		(net "GND")
	)
	(via
		(at 216.824814 -213.46668)
		(size 0.4572)
		(drill 0.2032)
		(layers "F.Cu" "B.Cu")
		(net "GND")
	)
	(via
		(at 46.964346 -304.416714)
		(size 0.4572)
		(drill 0.2032)
		(layers "F.Cu" "B.Cu")
		(net "GND")
	)
	(via
		(at 458.455014 -212.616796)
		(size 0.4572)
		(drill 0.2032)
		(layers "F.Cu" "B.Cu")
		(net "GND")
	)
	(via
		(at 52.465478 -403.883876)
		(size 0.4064)
		(drill 0.2032)
		(layers "F.Cu" "B.Cu")
		(net "GND")
	)
	(via
		(at 58.666888 -10.16508)
		(size 0.508)
		(drill 0.254)
		(layers "F.Cu" "B.Cu")
		(net "GND")
	)
	(via
		(at 115.342162 -236.565186)
		(size 0.4572)
		(drill 0.2032)
		(layers "F.Cu" "B.Cu")
		(net "GND")
	)
	(via
		(at 264.729214 -206.666592)
		(size 0.4572)
		(drill 0.2032)
		(layers "F.Cu" "B.Cu")
		(net "GND")
	)
	(via
		(at 90.964766 -219.506038)
		(size 0.4572)
		(drill 0.2032)
		(layers "F.Cu" "B.Cu")
		(net "GND")
	)
	(via
		(at 238.60252 -387.37794)
		(size 0.508)
		(drill 0.254)
		(layers "F.Cu" "B.Cu")
		(net "GND")
	)
	(via
		(at 199.527414 -314.616592)
		(size 0.4572)
		(drill 0.2032)
		(layers "F.Cu" "B.Cu")
		(net "GND")
	)
	(via
		(at 46.964346 -292.516814)
		(size 0.4572)
		(drill 0.2032)
		(layers "F.Cu" "B.Cu")
		(net "GND")
	)
	(via
		(at 22.123146 -206.666592)
		(size 0.4572)
		(drill 0.2032)
		(layers "F.Cu" "B.Cu")
		(net "GND")
	)
	(via
		(at 260.99008 -31.173928)
		(size 0.508)
		(drill 0.254)
		(layers "F.Cu" "B.Cu")
		(net "GND")
	)
	(via
		(at 58.666888 -7.215124)
		(size 0.508)
		(drill 0.254)
		(layers "F.Cu" "B.Cu")
		(net "GND")
	)
	(via
		(at 161.808414 -289.966654)
		(size 0.4572)
		(drill 0.2032)
		(layers "F.Cu" "B.Cu")
		(net "GND")
	)
	(via
		(at 148.785326 -403.249892)
		(size 0.4572)
		(drill 0.254)
		(layers "F.Cu" "B.Cu")
		(net "GND")
	)
	(via
		(at 337.581748 -53.149246)
		(size 0.4572)
		(drill 0.2032)
		(layers "F.Cu" "B.Cu")
		(net "GND")
	)
	(via
		(at 363.2835 -408.544268)
		(size 0.508)
		(drill 0.254)
		(layers "F.Cu" "B.Cu")
		(net "GND")
	)
	(via
		(at 450.911214 -242.3668)
		(size 0.4572)
		(drill 0.2032)
		(layers "F.Cu" "B.Cu")
		(net "GND")
	)
	(via
		(at 165.252146 -272.116804)
		(size 0.4572)
		(drill 0.2032)
		(layers "F.Cu" "B.Cu")
		(net "GND")
	)
	(via
		(at 369.918234 -216.25052)
		(size 0.4572)
		(drill 0.2032)
		(layers "F.Cu" "B.Cu")
		(net "GND")
	)
	(via
		(at 172.795946 -285.716726)
		(size 0.4572)
		(drill 0.2032)
		(layers "F.Cu" "B.Cu")
		(net "GND")
	)
	(via
		(at 294.904414 -258.516628)
		(size 0.4572)
		(drill 0.2032)
		(layers "F.Cu" "B.Cu")
		(net "GND")
	)
	(via
		(at 46.964346 -263.616694)
		(size 0.4572)
		(drill 0.2032)
		(layers "F.Cu" "B.Cu")
		(net "GND")
	)
	(via
		(at 140.43533 -441.225432)
		(size 0.508)
		(drill 0.254)
		(layers "F.Cu" "B.Cu")
		(net "GND")
	)
	(via
		(at 449.677282 -280.61666)
		(size 0.4572)
		(drill 0.2032)
		(layers "F.Cu" "B.Cu")
		(net "GND")
	)
	(via
		(at 114.30508 -398.884648)
		(size 0.508)
		(drill 0.254)
		(layers "F.Cu" "B.Cu")
		(net "GND")
	)
	(via
		(at 449.677282 -266.1666)
		(size 0.4572)
		(drill 0.2032)
		(layers "F.Cu" "B.Cu")
		(net "GND")
	)
	(via
		(at 379.956822 -407.638504)
		(size 0.4572)
		(drill 0.254)
		(layers "F.Cu" "B.Cu")
		(net "GND")
	)
	(via
		(at 59.842146 -233.016806)
		(size 0.4572)
		(drill 0.2032)
		(layers "F.Cu" "B.Cu")
		(net "GND")
	)
	(via
		(at 127.616966 -222.761556)
		(size 0.4572)
		(drill 0.2032)
		(layers "F.Cu" "B.Cu")
		(net "GND")
	)
	(via
		(at 14.579346 -278.066754)
		(size 0.4572)
		(drill 0.2032)
		(layers "F.Cu" "B.Cu")
		(net "GND")
	)
	(via
		(at 9.245346 -195.616576)
		(size 0.4572)
		(drill 0.2032)
		(layers "F.Cu" "B.Cu")
		(net "GND")
	)
	(via
		(at 180.339746 -267.016738)
		(size 0.4572)
		(drill 0.2032)
		(layers "F.Cu" "B.Cu")
		(net "GND")
	)
	(via
		(at 11.135614 -271.266666)
		(size 0.4572)
		(drill 0.2032)
		(layers "F.Cu" "B.Cu")
		(net "GND")
	)
	(via
		(at 212.724746 -212.616796)
		(size 0.4572)
		(drill 0.2032)
		(layers "F.Cu" "B.Cu")
		(net "GND")
	)
	(via
		(at 88.255094 -271.825212)
		(size 0.4572)
		(drill 0.2032)
		(layers "F.Cu" "B.Cu")
		(net "GND")
	)
	(via
		(at 434.589682 -269.566644)
		(size 0.4572)
		(drill 0.2032)
		(layers "F.Cu" "B.Cu")
		(net "GND")
	)
	(via
		(at 52.082446 -276.366732)
		(size 0.4572)
		(drill 0.2032)
		(layers "F.Cu" "B.Cu")
		(net "GND")
	)
	(via
		(at 143.34998 -438.651396)
		(size 0.4572)
		(drill 0.2032)
		(layers "F.Cu" "B.Cu")
		(net "GND")
	)
	(via
		(at 94.253812 -238.225584)
		(size 0.4572)
		(drill 0.2032)
		(layers "F.Cu" "B.Cu")
		(net "GND")
	)
	(via
		(at 415.041334 -5.585714)
		(size 0.508)
		(drill 0.254)
		(layers "F.Cu" "B.Cu")
		(net "GND")
	)
	(via
		(at 216.824814 -238.116618)
		(size 0.4572)
		(drill 0.2032)
		(layers "F.Cu" "B.Cu")
		(net "GND")
	)
	(via
		(at 291.510974 -322.499736)
		(size 0.4572)
		(drill 0.2032)
		(layers "F.Cu" "B.Cu")
		(net "GND")
	)
	(via
		(at 326.591422 -35.956748)
		(size 0.49022)
		(drill 0.254)
		(layers "F.Cu" "B.Cu")
		(net "GND")
	)
	(via
		(at 26.004266 -17.61236)
		(size 0.508)
		(drill 0.254)
		(layers "F.Cu" "B.Cu")
		(net "GND")
	)
	(via
		(at 296.794682 -306.96662)
		(size 0.4572)
		(drill 0.2032)
		(layers "F.Cu" "B.Cu")
		(net "GND")
	)
	(via
		(at 92.014294 -255.547622)
		(size 0.4572)
		(drill 0.2032)
		(layers "F.Cu" "B.Cu")
		(net "GND")
	)
	(via
		(at 187.758324 -154.43708)
		(size 0.508)
		(drill 0.254)
		(layers "F.Cu" "B.Cu")
		(net "GND")
	)
	(via
		(at 423.836084 -360.937556)
		(size 0.49022)
		(drill 0.254)
		(layers "F.Cu" "B.Cu")
		(net "GND")
	)
	(via
		(at 296.794682 -262.76681)
		(size 0.4572)
		(drill 0.2032)
		(layers "F.Cu" "B.Cu")
		(net "GND")
	)
	(via
		(at 131.752086 -407.638504)
		(size 0.4572)
		(drill 0.254)
		(layers "F.Cu" "B.Cu")
		(net "GND")
	)
	(via
		(at 254.975614 -268.71676)
		(size 0.4572)
		(drill 0.2032)
		(layers "F.Cu" "B.Cu")
		(net "GND")
	)
	(via
		(at 29.666946 -248.31675)
		(size 0.4572)
		(drill 0.2032)
		(layers "F.Cu" "B.Cu")
		(net "GND")
	)
	(via
		(at 134.195566 -235.783882)
		(size 0.4572)
		(drill 0.2032)
		(layers "F.Cu" "B.Cu")
		(net "GND")
	)
	(via
		(at 15.5575 -100.620068)
		(size 0.508)
		(drill 0.254)
		(layers "F.Cu" "B.Cu")
		(net "GND")
	)
	(via
		(at 74.843132 -162.003486)
		(size 0.508)
		(drill 0.254)
		(layers "F.Cu" "B.Cu")
		(net "GND")
	)
	(via
		(at 390.563608 -338.964016)
		(size 0.508)
		(drill 0.254)
		(layers "F.Cu" "B.Cu")
		(net "GND")
	)
	(via
		(at 314.092082 -291.666676)
		(size 0.4572)
		(drill 0.2032)
		(layers "F.Cu" "B.Cu")
		(net "GND")
	)
	(via
		(at 38.395402 -350.826578)
		(size 0.508)
		(drill 0.254)
		(layers "F.Cu" "B.Cu")
		(net "GND")
	)
	(via
		(at 43.520614 -271.266666)
		(size 0.4572)
		(drill 0.2032)
		(layers "F.Cu" "B.Cu")
		(net "GND")
	)
	(via
		(at 90.964512 -245.55069)
		(size 0.4572)
		(drill 0.2032)
		(layers "F.Cu" "B.Cu")
		(net "GND")
	)
	(via
		(at 18.679414 -211.766658)
		(size 0.4572)
		(drill 0.2032)
		(layers "F.Cu" "B.Cu")
		(net "GND")
	)
	(via
		(at 50.845466 -400.224244)
		(size 0.4572)
		(drill 0.254)
		(layers "F.Cu" "B.Cu")
		(net "GND")
	)
	(via
		(at 453.121014 -236.416596)
		(size 0.4572)
		(drill 0.2032)
		(layers "F.Cu" "B.Cu")
		(net "GND")
	)
	(via
		(at 306.845716 -400.224244)
		(size 0.4572)
		(drill 0.254)
		(layers "F.Cu" "B.Cu")
		(net "GND")
	)
	(via
		(at 341.724234 -226.017328)
		(size 0.4572)
		(drill 0.2032)
		(layers "F.Cu" "B.Cu")
		(net "GND")
	)
	(via
		(at 254.975614 -220.266768)
		(size 0.4572)
		(drill 0.2032)
		(layers "F.Cu" "B.Cu")
		(net "GND")
	)
	(via
		(at 139.004548 -275.080984)
		(size 0.4572)
		(drill 0.2032)
		(layers "F.Cu" "B.Cu")
		(net "GND")
	)
	(via
		(at 373.237506 -170.246548)
		(size 0.508)
		(drill 0.254)
		(layers "F.Cu" "B.Cu")
		(net "GND")
	)
	(via
		(at 28.433014 -196.466714)
		(size 0.4572)
		(drill 0.2032)
		(layers "F.Cu" "B.Cu")
		(net "GND")
	)
	(via
		(at 370.858034 -226.017328)
		(size 0.4572)
		(drill 0.2032)
		(layers "F.Cu" "B.Cu")
		(net "GND")
	)
	(via
		(at 294.904414 -309.51678)
		(size 0.4572)
		(drill 0.2032)
		(layers "F.Cu" "B.Cu")
		(net "GND")
	)
	(via
		(at 40.212772 -351.608644)
		(size 0.49022)
		(drill 0.254)
		(layers "F.Cu" "B.Cu")
		(net "GND")
	)
	(via
		(at 347.363034 -242.294918)
		(size 0.4572)
		(drill 0.2032)
		(layers "F.Cu" "B.Cu")
		(net "GND")
	)
	(via
		(at 156.090874 -53.309012)
		(size 0.508)
		(drill 0.254)
		(layers "F.Cu" "B.Cu")
		(net "GND")
	)
	(via
		(at 405.648414 -208.366614)
		(size 0.4572)
		(drill 0.2032)
		(layers "F.Cu" "B.Cu")
		(net "GND")
	)
	(via
		(at 13.345414 -266.1666)
		(size 0.4572)
		(drill 0.2032)
		(layers "F.Cu" "B.Cu")
		(net "GND")
	)
	(via
		(at 464.764882 -249.166634)
		(size 0.4572)
		(drill 0.2032)
		(layers "F.Cu" "B.Cu")
		(net "GND")
	)
	(via
		(at 287.360614 -295.06672)
		(size 0.4572)
		(drill 0.2032)
		(layers "F.Cu" "B.Cu")
		(net "GND")
	)
	(via
		(at 179.105814 -244.066568)
		(size 0.4572)
		(drill 0.2032)
		(layers "F.Cu" "B.Cu")
		(net "GND")
	)
	(via
		(at 167.461946 -304.416714)
		(size 0.4572)
		(drill 0.2032)
		(layers "F.Cu" "B.Cu")
		(net "GND")
	)
	(via
		(at 222.535496 -16.782288)
		(size 0.508)
		(drill 0.254)
		(layers "F.Cu" "B.Cu")
		(net "GND")
	)
	(via
		(at 306.548282 -266.1666)
		(size 0.4572)
		(drill 0.2032)
		(layers "F.Cu" "B.Cu")
		(net "GND")
	)
	(via
		(at 131.015994 -271.011396)
		(size 0.4572)
		(drill 0.2032)
		(layers "F.Cu" "B.Cu")
		(net "GND")
	)
	(via
		(at 406.607772 -16.967454)
		(size 0.508)
		(drill 0.254)
		(layers "F.Cu" "B.Cu")
		(net "GND")
	)
	(via
		(at 216.824814 -205.816708)
		(size 0.4572)
		(drill 0.2032)
		(layers "F.Cu" "B.Cu")
		(net "GND")
	)
	(via
		(at 442.133482 -238.116618)
		(size 0.4572)
		(drill 0.2032)
		(layers "F.Cu" "B.Cu")
		(net "GND")
	)
	(via
		(at 435.823614 -244.916706)
		(size 0.4572)
		(drill 0.2032)
		(layers "F.Cu" "B.Cu")
		(net "GND")
	)
	(via
		(at 92.954348 -263.686544)
		(size 0.4572)
		(drill 0.2032)
		(layers "F.Cu" "B.Cu")
		(net "GND")
	)
	(via
		(at 274.163282 -262.76681)
		(size 0.4572)
		(drill 0.2032)
		(layers "F.Cu" "B.Cu")
		(net "GND")
	)
	(via
		(at 137.124948 -265.314176)
		(size 0.4318)
		(drill 0.2032)
		(layers "F.Cu" "B.Cu")
		(net "GND")
	)
	(via
		(at 118.328694 -281.59202)
		(size 0.4572)
		(drill 0.2032)
		(layers "F.Cu" "B.Cu")
		(net "GND")
	)
	(via
		(at 13.345414 -271.266666)
		(size 0.4572)
		(drill 0.2032)
		(layers "F.Cu" "B.Cu")
		(net "GND")
	)
	(via
		(at 292.704774 -322.499736)
		(size 0.4572)
		(drill 0.2032)
		(layers "F.Cu" "B.Cu")
		(net "GND")
	)
	(via
		(at 369.541806 -167.312848)
		(size 0.508)
		(drill 0.254)
		(layers "F.Cu" "B.Cu")
		(net "GND")
	)
	(via
		(at 384.485134 -249.620024)
		(size 0.4572)
		(drill 0.2032)
		(layers "F.Cu" "B.Cu")
		(net "GND")
	)
	(via
		(at 348.77248 -233.34218)
		(size 0.4572)
		(drill 0.2032)
		(layers "F.Cu" "B.Cu")
		(net "GND")
	)
	(via
		(at 7.035546 -263.616694)
		(size 0.4572)
		(drill 0.2032)
		(layers "F.Cu" "B.Cu")
		(net "GND")
	)
	(via
		(at 299.004482 -249.166634)
		(size 0.4572)
		(drill 0.2032)
		(layers "F.Cu" "B.Cu")
		(net "GND")
	)
	(via
		(at 327.91654 -336.119978)
		(size 0.508)
		(drill 0.254)
		(layers "F.Cu" "B.Cu")
		(net "GND")
	)
	(via
		(at 384.485134 -244.73662)
		(size 0.4572)
		(drill 0.2032)
		(layers "F.Cu" "B.Cu")
		(net "GND")
	)
	(via
		(at 428.279814 -258.516628)
		(size 0.4572)
		(drill 0.2032)
		(layers "F.Cu" "B.Cu")
		(net "GND")
	)
	(via
		(at 281.707082 -288.266632)
		(size 0.4572)
		(drill 0.2032)
		(layers "F.Cu" "B.Cu")
		(net "GND")
	)
	(via
		(at 76.250038 -438.651396)
		(size 0.4572)
		(drill 0.2032)
		(layers "F.Cu" "B.Cu")
		(net "GND")
	)
	(via
		(at 186.649614 -266.1666)
		(size 0.4572)
		(drill 0.2032)
		(layers "F.Cu" "B.Cu")
		(net "GND")
	)
	(via
		(at 257.185414 -260.21665)
		(size 0.4572)
		(drill 0.2032)
		(layers "F.Cu" "B.Cu")
		(net "GND")
	)
	(via
		(at 314.606686 -12.544552)
		(size 0.508)
		(drill 0.254)
		(layers "F.Cu" "B.Cu")
		(net "GND")
	)
	(via
		(at 35.976814 -204.116686)
		(size 0.4572)
		(drill 0.2032)
		(layers "F.Cu" "B.Cu")
		(net "GND")
	)
	(via
		(at 27.547062 -7.215124)
		(size 0.508)
		(drill 0.254)
		(layers "F.Cu" "B.Cu")
		(net "GND")
	)
	(via
		(at 51.064414 -235.566712)
		(size 0.4572)
		(drill 0.2032)
		(layers "F.Cu" "B.Cu")
		(net "GND")
	)
	(via
		(at 191.983614 -288.266632)
		(size 0.4572)
		(drill 0.2032)
		(layers "F.Cu" "B.Cu")
		(net "GND")
	)
	(via
		(at 236.025436 -125.70841)
		(size 0.508)
		(drill 0.254)
		(layers "F.Cu" "B.Cu")
		(net "GND")
	)
	(via
		(at 141.064488 -341.131398)
		(size 0.508)
		(drill 0.254)
		(layers "F.Cu" "B.Cu")
		(net "GND")
	)
	(via
		(at 39.420546 -244.916706)
		(size 0.4572)
		(drill 0.2032)
		(layers "F.Cu" "B.Cu")
		(net "GND")
	)
	(via
		(at 92.014294 -270.19758)
		(size 0.4572)
		(drill 0.2032)
		(layers "F.Cu" "B.Cu")
		(net "GND")
	)
	(via
		(at 86.735412 -217.064336)
		(size 0.4572)
		(drill 0.2032)
		(layers "F.Cu" "B.Cu")
		(net "GND")
	)
	(via
		(at 416.556952 -9.424924)
		(size 0.508)
		(drill 0.254)
		(layers "F.Cu" "B.Cu")
		(net "GND")
	)
	(via
		(at 445.577214 -300.166786)
		(size 0.4572)
		(drill 0.2032)
		(layers "F.Cu" "B.Cu")
		(net "GND")
	)
	(via
		(at 273.748754 -132.64769)
		(size 0.508)
		(drill 0.254)
		(layers "F.Cu" "B.Cu")
		(net "GND")
	)
	(via
		(at 419.502082 -258.516628)
		(size 0.4572)
		(drill 0.2032)
		(layers "F.Cu" "B.Cu")
		(net "GND")
	)
	(via
		(at 214.615014 -291.666676)
		(size 0.4572)
		(drill 0.2032)
		(layers "F.Cu" "B.Cu")
		(net "GND")
	)
	(via
		(at 157.708346 -214.316564)
		(size 0.4572)
		(drill 0.2032)
		(layers "F.Cu" "B.Cu")
		(net "GND")
	)
	(via
		(at 95.193612 -249.620024)
		(size 0.4572)
		(drill 0.2032)
		(layers "F.Cu" "B.Cu")
		(net "GND")
	)
	(via
		(at 53.256942 -19.770344)
		(size 0.508)
		(drill 0.254)
		(layers "F.Cu" "B.Cu")
		(net "GND")
	)
	(via
		(at 88.250014 -433.899564)
		(size 0.4572)
		(drill 0.2032)
		(layers "F.Cu" "B.Cu")
		(net "GND")
	)
	(via
		(at 43.520614 -239.81664)
		(size 0.4572)
		(drill 0.2032)
		(layers "F.Cu" "B.Cu")
		(net "GND")
	)
	(via
		(at 276.373082 -204.116686)
		(size 0.4572)
		(drill 0.2032)
		(layers "F.Cu" "B.Cu")
		(net "GND")
	)
	(via
		(at 169.352214 -286.56661)
		(size 0.4572)
		(drill 0.2032)
		(layers "F.Cu" "B.Cu")
		(net "GND")
	)
	(via
		(at 381.305562 -260.430772)
		(size 0.4572)
		(drill 0.2032)
		(layers "F.Cu" "B.Cu")
		(net "GND")
	)
	(via
		(at 132.210302 -401.492212)
		(size 0.4572)
		(drill 0.254)
		(layers "F.Cu" "B.Cu")
		(net "GND")
	)
	(via
		(at 266.619482 -275.516594)
		(size 0.4572)
		(drill 0.2032)
		(layers "F.Cu" "B.Cu")
		(net "GND")
	)
	(via
		(at 101.617018 -332.363826)
		(size 0.508)
		(drill 0.254)
		(layers "F.Cu" "B.Cu")
		(net "GND")
	)
	(via
		(at 171.562014 -271.266666)
		(size 0.4572)
		(drill 0.2032)
		(layers "F.Cu" "B.Cu")
		(net "GND")
	)
	(via
		(at 372.155466 -54.127908)
		(size 0.508)
		(drill 0.254)
		(layers "F.Cu" "B.Cu")
		(net "GND")
	)
	(via
		(at 383.54508 -236.597952)
		(size 0.4572)
		(drill 0.2032)
		(layers "F.Cu" "B.Cu")
		(net "GND")
	)
	(via
		(at 357.717344 -329.078844)
		(size 0.508)
		(drill 0.254)
		(layers "F.Cu" "B.Cu")
		(net "GND")
	)
	(via
		(at 412.990792 -360.687112)
		(size 0.508)
		(drill 0.254)
		(layers "F.Cu" "B.Cu")
		(net "GND")
	)
	(via
		(at 419.502082 -202.416664)
		(size 0.4572)
		(drill 0.2032)
		(layers "F.Cu" "B.Cu")
		(net "GND")
	)
	(via
		(at 210.514946 -214.316564)
		(size 0.4572)
		(drill 0.2032)
		(layers "F.Cu" "B.Cu")
		(net "GND")
	)
	(via
		(at 444.771272 -67.576192)
		(size 0.508)
		(drill 0.254)
		(layers "F.Cu" "B.Cu")
		(net "GND")
	)
	(via
		(at 266.619482 -306.96662)
		(size 0.4572)
		(drill 0.2032)
		(layers "F.Cu" "B.Cu")
		(net "GND")
	)
	(via
		(at 44.754546 -229.616762)
		(size 0.4572)
		(drill 0.2032)
		(layers "F.Cu" "B.Cu")
		(net "GND")
	)
	(via
		(at 352.062034 -219.506038)
		(size 0.4572)
		(drill 0.2032)
		(layers "F.Cu" "B.Cu")
		(net "GND")
	)
	(via
		(at 379.02134 -335.187036)
		(size 0.49022)
		(drill 0.254)
		(layers "F.Cu" "B.Cu")
		(net "GND")
	)
	(via
		(at 53.100732 -0.76454)
		(size 0.508)
		(drill 0.254)
		(layers "F.Cu" "B.Cu")
		(net "GND")
	)
	(via
		(at 53.908706 -400.224244)
		(size 0.4572)
		(drill 0.254)
		(layers "F.Cu" "B.Cu")
		(net "GND")
	)
	(via
		(at 424.836082 -291.666676)
		(size 0.4572)
		(drill 0.2032)
		(layers "F.Cu" "B.Cu")
		(net "GND")
	)
	(via
		(at 80.28432 -146.878548)
		(size 0.508)
		(drill 0.254)
		(layers "F.Cu" "B.Cu")
		(net "GND")
	)
	(via
		(at 53.539136 -6.090412)
		(size 0.508)
		(drill 0.254)
		(layers "F.Cu" "B.Cu")
		(net "GND")
	)
	(via
		(at 409.69692 -159.095948)
		(size 0.508)
		(drill 0.254)
		(layers "F.Cu" "B.Cu")
		(net "GND")
	)
	(via
		(at 424.836082 -198.166736)
		(size 0.4572)
		(drill 0.2032)
		(layers "F.Cu" "B.Cu")
		(net "GND")
	)
	(via
		(at 46.964346 -258.516628)
		(size 0.4572)
		(drill 0.2032)
		(layers "F.Cu" "B.Cu")
		(net "GND")
	)
	(via
		(at 88.615012 -244.73662)
		(size 0.4572)
		(drill 0.2032)
		(layers "F.Cu" "B.Cu")
		(net "GND")
	)
	(via
		(at 436.368952 -388.73303)
		(size 0.508)
		(drill 0.254)
		(layers "F.Cu" "B.Cu")
		(net "GND")
	)
	(via
		(at 448.78752 -59.649868)
		(size 0.508)
		(drill 0.254)
		(layers "F.Cu" "B.Cu")
		(net "GND")
	)
	(via
		(at 373.291354 -166.621968)
		(size 0.508)
		(drill 0.254)
		(layers "F.Cu" "B.Cu")
		(net "GND")
	)
	(via
		(at 26.223214 -272.966688)
		(size 0.4572)
		(drill 0.2032)
		(layers "F.Cu" "B.Cu")
		(net "GND")
	)
	(via
		(at 415.402014 -210.916774)
		(size 0.4572)
		(drill 0.2032)
		(layers "F.Cu" "B.Cu")
		(net "GND")
	)
	(via
		(at 453.121014 -278.066754)
		(size 0.4572)
		(drill 0.2032)
		(layers "F.Cu" "B.Cu")
		(net "GND")
	)
	(via
		(at 381.195834 -222.761556)
		(size 0.4572)
		(drill 0.2032)
		(layers "F.Cu" "B.Cu")
		(net "GND")
	)
	(via
		(at 199.527414 -267.866622)
		(size 0.4572)
		(drill 0.2032)
		(layers "F.Cu" "B.Cu")
		(net "GND")
	)
	(via
		(at 129.147062 -401.492212)
		(size 0.4572)
		(drill 0.254)
		(layers "F.Cu" "B.Cu")
		(net "GND")
	)
	(via
		(at 167.461946 -317.166752)
		(size 0.4572)
		(drill 0.2032)
		(layers "F.Cu" "B.Cu")
		(net "GND")
	)
	(via
		(at 108.43387 -252.075188)
		(size 0.4572)
		(drill 0.2032)
		(layers "F.Cu" "B.Cu")
		(net "GND")
	)
	(via
		(at 91.434412 -236.597952)
		(size 0.4572)
		(drill 0.2032)
		(layers "F.Cu" "B.Cu")
		(net "GND")
	)
	(via
		(at 300.238414 -261.916672)
		(size 0.4572)
		(drill 0.2032)
		(layers "F.Cu" "B.Cu")
		(net "GND")
	)
	(via
		(at 85.16239 -53.494686)
		(size 0.508)
		(drill 0.254)
		(layers "F.Cu" "B.Cu")
		(net "GND")
	)
	(via
		(at 287.360614 -290.816792)
		(size 0.4572)
		(drill 0.2032)
		(layers "F.Cu" "B.Cu")
		(net "GND")
	)
	(via
		(at 346.667836 -403.249892)
		(size 0.4572)
		(drill 0.254)
		(layers "F.Cu" "B.Cu")
		(net "GND")
	)
	(via
		(at 395.731238 -403.249892)
		(size 0.4572)
		(drill 0.254)
		(layers "F.Cu" "B.Cu")
		(net "GND")
	)
	(via
		(at 358.170734 -217.064336)
		(size 0.4572)
		(drill 0.2032)
		(layers "F.Cu" "B.Cu")
		(net "GND")
	)
	(via
		(at 53.811678 -407.00452)
		(size 0.4064)
		(drill 0.2032)
		(layers "F.Cu" "B.Cu")
		(net "GND")
	)
	(via
		(at 442.464952 -394.876274)
		(size 0.6604)
		(drill 0.3302)
		(layers "F.Cu" "B.Cu")
		(net "GND")
	)
	(via
		(at 253.4666 -101.78288)
		(size 0.508)
		(drill 0.254)
		(layers "F.Cu" "B.Cu")
		(net "GND")
	)
	(via
		(at 150.131526 -407.638504)
		(size 0.4572)
		(drill 0.254)
		(layers "F.Cu" "B.Cu")
		(net "GND")
	)
	(via
		(at 276.373082 -235.566712)
		(size 0.4572)
		(drill 0.2032)
		(layers "F.Cu" "B.Cu")
		(net "GND")
	)
	(via
		(at 14.579346 -285.716726)
		(size 0.4572)
		(drill 0.2032)
		(layers "F.Cu" "B.Cu")
		(net "GND")
	)
	(via
		(at 113.629694 -281.59202)
		(size 0.4572)
		(drill 0.2032)
		(layers "F.Cu" "B.Cu")
		(net "GND")
	)
	(via
		(at 134.195566 -227.64496)
		(size 0.4572)
		(drill 0.2032)
		(layers "F.Cu" "B.Cu")
		(net "GND")
	)
	(via
		(at 349.352362 -273.453098)
		(size 0.4572)
		(drill 0.2032)
		(layers "F.Cu" "B.Cu")
		(net "GND")
	)
	(via
		(at 26.223214 -210.066636)
		(size 0.4572)
		(drill 0.2032)
		(layers "F.Cu" "B.Cu")
		(net "GND")
	)
	(via
		(at 438.033414 -220.266768)
		(size 0.4572)
		(drill 0.2032)
		(layers "F.Cu" "B.Cu")
		(net "GND")
	)
	(via
		(at 447.467482 -200.716642)
		(size 0.4572)
		(drill 0.2032)
		(layers "F.Cu" "B.Cu")
		(net "GND")
	)
	(via
		(at 309.992014 -250.016772)
		(size 0.4572)
		(drill 0.2032)
		(layers "F.Cu" "B.Cu")
		(net "GND")
	)
	(via
		(at 7.610348 -101.854)
		(size 0.508)
		(drill 0.254)
		(layers "F.Cu" "B.Cu")
		(net "GND")
	)
	(via
		(at 318.737488 -400.858228)
		(size 0.4064)
		(drill 0.2032)
		(layers "F.Cu" "B.Cu")
		(net "GND")
	)
	(via
		(at 428.279814 -281.466798)
		(size 0.4572)
		(drill 0.2032)
		(layers "F.Cu" "B.Cu")
		(net "GND")
	)
	(via
		(at 414.074356 -159.996378)
		(size 0.49022)
		(drill 0.254)
		(layers "F.Cu" "B.Cu")
		(net "GND")
	)
	(via
		(at 160.75533 -441.225432)
		(size 0.508)
		(drill 0.254)
		(layers "F.Cu" "B.Cu")
		(net "GND")
	)
	(via
		(at 314.936378 -24.132032)
		(size 0.508)
		(drill 0.254)
		(layers "F.Cu" "B.Cu")
		(net "GND")
	)
	(via
		(at 41.310814 -306.96662)
		(size 0.4572)
		(drill 0.2032)
		(layers "F.Cu" "B.Cu")
		(net "GND")
	)
	(via
		(at 416.715702 -410.664152)
		(size 0.4572)
		(drill 0.254)
		(layers "F.Cu" "B.Cu")
		(net "GND")
	)
	(via
		(at 171.50715 -14.759432)
		(size 0.508)
		(drill 0.254)
		(layers "F.Cu" "B.Cu")
		(net "GND")
	)
	(via
		(at 336.530696 -339.114638)
		(size 0.49022)
		(drill 0.254)
		(layers "F.Cu" "B.Cu")
		(net "GND")
	)
	(via
		(at 79.67345 -400.224244)
		(size 0.4572)
		(drill 0.254)
		(layers "F.Cu" "B.Cu")
		(net "GND")
	)
	(via
		(at 28.433014 -294.216582)
		(size 0.4572)
		(drill 0.2032)
		(layers "F.Cu" "B.Cu")
		(net "GND")
	)
	(via
		(at 59.385962 -150.93188)
		(size 0.508)
		(drill 0.254)
		(layers "F.Cu" "B.Cu")
		(net "GND")
	)
	(via
		(at 320.444876 -409.396184)
		(size 0.4572)
		(drill 0.254)
		(layers "F.Cu" "B.Cu")
		(net "GND")
	)
	(via
		(at 124.437394 -267.755878)
		(size 0.4572)
		(drill 0.2032)
		(layers "F.Cu" "B.Cu")
		(net "GND")
	)
	(via
		(at 40.988996 -393.464542)
		(size 0.508)
		(drill 0.254)
		(layers "F.Cu" "B.Cu")
		(net "GND")
	)
	(via
		(at 43.520614 -277.216616)
		(size 0.4572)
		(drill 0.2032)
		(layers "F.Cu" "B.Cu")
		(net "GND")
	)
	(via
		(at 195.427346 -206.666592)
		(size 0.4572)
		(drill 0.2032)
		(layers "F.Cu" "B.Cu")
		(net "GND")
	)
	(via
		(at 264.729214 -217.716608)
		(size 0.4572)
		(drill 0.2032)
		(layers "F.Cu" "B.Cu")
		(net "GND")
	)
	(via
		(at 22.123146 -227.066602)
		(size 0.4572)
		(drill 0.2032)
		(layers "F.Cu" "B.Cu")
		(net "GND")
	)
	(via
		(at 74.89317 -407.638504)
		(size 0.4572)
		(drill 0.254)
		(layers "F.Cu" "B.Cu")
		(net "GND")
	)
	(via
		(at 150.85695 -12.495022)
		(size 0.508)
		(drill 0.254)
		(layers "F.Cu" "B.Cu")
		(net "GND")
	)
	(via
		(at 228.615494 -131.546092)
		(size 0.508)
		(drill 0.254)
		(layers "F.Cu" "B.Cu")
		(net "GND")
	)
	(via
		(at 349.242634 -219.506038)
		(size 0.4572)
		(drill 0.2032)
		(layers "F.Cu" "B.Cu")
		(net "GND")
	)
	(via
		(at 134.195566 -229.272846)
		(size 0.4572)
		(drill 0.2032)
		(layers "F.Cu" "B.Cu")
		(net "GND")
	)
	(via
		(at 93.784166 -232.528364)
		(size 0.4572)
		(drill 0.2032)
		(layers "F.Cu" "B.Cu")
		(net "GND")
	)
	(via
		(at 270.063214 -233.016806)
		(size 0.4572)
		(drill 0.2032)
		(layers "F.Cu" "B.Cu")
		(net "GND")
	)
	(via
		(at 453.81926 -58.872628)
		(size 0.508)
		(drill 0.254)
		(layers "F.Cu" "B.Cu")
		(net "GND")
	)
	(via
		(at 289.250882 -204.116686)
		(size 0.4572)
		(drill 0.2032)
		(layers "F.Cu" "B.Cu")
		(net "GND")
	)
	(via
		(at 84.250022 -435.0512)
		(size 0.4572)
		(drill 0.2032)
		(layers "F.Cu" "B.Cu")
		(net "GND")
	)
	(via
		(at 120.270778 -263.125712)
		(size 0.4572)
		(drill 0.2032)
		(layers "F.Cu" "B.Cu")
		(net "GND")
	)
	(via
		(at 86.265766 -237.411768)
		(size 0.4572)
		(drill 0.2032)
		(layers "F.Cu" "B.Cu")
		(net "GND")
	)
	(via
		(at 347.92666 -404.51786)
		(size 0.4572)
		(drill 0.254)
		(layers "F.Cu" "B.Cu")
		(net "GND")
	)
	(via
		(at 26.223214 -219.41663)
		(size 0.4572)
		(drill 0.2032)
		(layers "F.Cu" "B.Cu")
		(net "GND")
	)
	(via
		(at 294.904414 -279.766776)
		(size 0.4572)
		(drill 0.2032)
		(layers "F.Cu" "B.Cu")
		(net "GND")
	)
	(via
		(at 127.616966 -235.783882)
		(size 0.4572)
		(drill 0.2032)
		(layers "F.Cu" "B.Cu")
		(net "GND")
	)
	(via
		(at 385.759452 -342.556084)
		(size 0.49022)
		(drill 0.254)
		(layers "F.Cu" "B.Cu")
		(net "GND")
	)
	(via
		(at 24.18588 -6.597396)
		(size 0.508)
		(drill 0.254)
		(layers "F.Cu" "B.Cu")
		(net "GND")
	)
	(via
		(at 361.569762 -279.964134)
		(size 0.4572)
		(drill 0.2032)
		(layers "F.Cu" "B.Cu")
		(net "GND")
	)
	(via
		(at 212.724746 -238.966756)
		(size 0.4572)
		(drill 0.2032)
		(layers "F.Cu" "B.Cu")
		(net "GND")
	)
	(via
		(at 81.294478 -21.793962)
		(size 0.508)
		(drill 0.254)
		(layers "F.Cu" "B.Cu")
		(net "GND")
	)
	(via
		(at 304.338482 -286.56661)
		(size 0.4572)
		(drill 0.2032)
		(layers "F.Cu" "B.Cu")
		(net "GND")
	)
	(via
		(at 149.349968 -438.499758)
		(size 0.4572)
		(drill 0.2032)
		(layers "F.Cu" "B.Cu")
		(net "GND")
	)
	(via
		(at 420.736014 -298.466764)
		(size 0.4572)
		(drill 0.2032)
		(layers "F.Cu" "B.Cu")
		(net "GND")
	)
	(via
		(at 374.85066 -102.829868)
		(size 0.508)
		(drill 0.254)
		(layers "F.Cu" "B.Cu")
		(net "GND")
	)
	(via
		(at 394.28801 -400.858228)
		(size 0.4064)
		(drill 0.2032)
		(layers "F.Cu" "B.Cu")
		(net "GND")
	)
	(via
		(at 7.035546 -220.266768)
		(size 0.4572)
		(drill 0.2032)
		(layers "F.Cu" "B.Cu")
		(net "GND")
	)
	(via
		(at 300.238414 -204.96657)
		(size 0.4572)
		(drill 0.2032)
		(layers "F.Cu" "B.Cu")
		(net "GND")
	)
	(via
		(at 31.876746 -250.016772)
		(size 0.4572)
		(drill 0.2032)
		(layers "F.Cu" "B.Cu")
		(net "GND")
	)
	(via
		(at 16.789146 -225.36658)
		(size 0.4572)
		(drill 0.2032)
		(layers "F.Cu" "B.Cu")
		(net "GND")
	)
	(via
		(at 311.882282 -262.76681)
		(size 0.4572)
		(drill 0.2032)
		(layers "F.Cu" "B.Cu")
		(net "GND")
	)
	(via
		(at 103.761794 -267.755878)
		(size 0.4572)
		(drill 0.2032)
		(layers "F.Cu" "B.Cu")
		(net "GND")
	)
	(via
		(at 409.748482 -230.466646)
		(size 0.4572)
		(drill 0.2032)
		(layers "F.Cu" "B.Cu")
		(net "GND")
	)
	(via
		(at 94.833948 -271.825212)
		(size 0.4572)
		(drill 0.2032)
		(layers "F.Cu" "B.Cu")
		(net "GND")
	)
	(via
		(at 272.273014 -208.366614)
		(size 0.4572)
		(drill 0.2032)
		(layers "F.Cu" "B.Cu")
		(net "GND")
	)
	(via
		(at 277.607014 -258.516628)
		(size 0.4572)
		(drill 0.2032)
		(layers "F.Cu" "B.Cu")
		(net "GND")
	)
	(via
		(at 358.613964 -441.225432)
		(size 0.508)
		(drill 0.254)
		(layers "F.Cu" "B.Cu")
		(net "GND")
	)
	(via
		(at 283.916882 -196.466714)
		(size 0.4572)
		(drill 0.2032)
		(layers "F.Cu" "B.Cu")
		(net "GND")
	)
	(via
		(at 192.55994 -43.849544)
		(size 0.508)
		(drill 0.254)
		(layers "F.Cu" "B.Cu")
		(net "GND")
	)
	(via
		(at 113.519966 -234.15625)
		(size 0.4572)
		(drill 0.2032)
		(layers "F.Cu" "B.Cu")
		(net "GND")
	)
	(via
		(at 435.823614 -309.51678)
		(size 0.4572)
		(drill 0.2032)
		(layers "F.Cu" "B.Cu")
		(net "GND")
	)
	(via
		(at 157.708346 -220.266768)
		(size 0.4572)
		(drill 0.2032)
		(layers "F.Cu" "B.Cu")
		(net "GND")
	)
	(via
		(at 113.068862 -338.86013)
		(size 0.508)
		(drill 0.254)
		(layers "F.Cu" "B.Cu")
		(net "GND")
	)
	(via
		(at 311.528968 -403.883876)
		(size 0.4064)
		(drill 0.2032)
		(layers "F.Cu" "B.Cu")
		(net "GND")
	)
	(via
		(at 83.925918 -96.642428)
		(size 0.508)
		(drill 0.254)
		(layers "F.Cu" "B.Cu")
		(net "GND")
	)
	(via
		(at 257.185414 -290.816792)
		(size 0.4572)
		(drill 0.2032)
		(layers "F.Cu" "B.Cu")
		(net "GND")
	)
	(via
		(at 432.685698 -58.972196)
		(size 0.508)
		(drill 0.254)
		(layers "F.Cu" "B.Cu")
		(net "GND")
	)
	(via
		(at 264.004552 -323.429376)
		(size 0.4572)
		(drill 0.2032)
		(layers "F.Cu" "B.Cu")
		(net "GND")
	)
	(via
		(at 91.544648 -264.50036)
		(size 0.4572)
		(drill 0.2032)
		(layers "F.Cu" "B.Cu")
		(net "GND")
	)
	(via
		(at 96.697038 -407.00452)
		(size 0.4064)
		(drill 0.2032)
		(layers "F.Cu" "B.Cu")
		(net "GND")
	)
	(via
		(at 428.279814 -210.916774)
		(size 0.4572)
		(drill 0.2032)
		(layers "F.Cu" "B.Cu")
		(net "GND")
	)
	(via
		(at 100.525834 -329.76312)
		(size 0.508)
		(drill 0.254)
		(layers "F.Cu" "B.Cu")
		(net "GND")
	)
	(via
		(at 175.005746 -244.916706)
		(size 0.4572)
		(drill 0.2032)
		(layers "F.Cu" "B.Cu")
		(net "GND")
	)
	(via
		(at 394.899642 -57.030366)
		(size 0.508)
		(drill 0.254)
		(layers "F.Cu" "B.Cu")
		(net "GND")
	)
	(via
		(at 390.349994 -429.147224)
		(size 0.4572)
		(drill 0.2032)
		(layers "F.Cu" "B.Cu")
		(net "GND")
	)
	(via
		(at 104.504236 -41.570148)
		(size 0.508)
		(drill 0.254)
		(layers "F.Cu" "B.Cu")
		(net "GND")
	)
	(via
		(at 129.606294 -258.80314)
		(size 0.4572)
		(drill 0.2032)
		(layers "F.Cu" "B.Cu")
		(net "GND")
	)
	(via
		(at 18.679414 -306.96662)
		(size 0.4572)
		(drill 0.2032)
		(layers "F.Cu" "B.Cu")
		(net "GND")
	)
	(via
		(at 232.2957 -60.940696)
		(size 0.508)
		(drill 0.254)
		(layers "F.Cu" "B.Cu")
		(net "GND")
	)
	(via
		(at 413.192214 -263.616694)
		(size 0.4572)
		(drill 0.2032)
		(layers "F.Cu" "B.Cu")
		(net "GND")
	)
	(via
		(at 167.690546 -208.366614)
		(size 0.4572)
		(drill 0.2032)
		(layers "F.Cu" "B.Cu")
		(net "GND")
	)
	(via
		(at 182.549546 -283.166566)
		(size 0.4572)
		(drill 0.2032)
		(layers "F.Cu" "B.Cu")
		(net "GND")
	)
	(via
		(at 94.364048 -280.778204)
		(size 0.4572)
		(drill 0.2032)
		(layers "F.Cu" "B.Cu")
		(net "GND")
	)
	(via
		(at 172.795946 -292.516814)
		(size 0.4572)
		(drill 0.2032)
		(layers "F.Cu" "B.Cu")
		(net "GND")
	)
	(via
		(at 390.277858 -149.609048)
		(size 0.508)
		(drill 0.254)
		(layers "F.Cu" "B.Cu")
		(net "GND")
	)
	(via
		(at 415.286444 -364.071662)
		(size 0.49022)
		(drill 0.254)
		(layers "F.Cu" "B.Cu")
		(net "GND")
	)
	(via
		(at 28.433014 -213.46668)
		(size 0.4572)
		(drill 0.2032)
		(layers "F.Cu" "B.Cu")
		(net "GND")
	)
	(via
		(at 351.232216 -278.336502)
		(size 0.4572)
		(drill 0.2032)
		(layers "F.Cu" "B.Cu")
		(net "GND")
	)
	(via
		(at 422.945814 -220.266768)
		(size 0.4572)
		(drill 0.2032)
		(layers "F.Cu" "B.Cu")
		(net "GND")
	)
	(via
		(at 61.212222 -153.54046)
		(size 0.508)
		(drill 0.254)
		(layers "F.Cu" "B.Cu")
		(net "GND")
	)
	(via
		(at 216.824814 -267.866622)
		(size 0.4572)
		(drill 0.2032)
		(layers "F.Cu" "B.Cu")
		(net "GND")
	)
	(via
		(at 439.923682 -202.416664)
		(size 0.4572)
		(drill 0.2032)
		(layers "F.Cu" "B.Cu")
		(net "GND")
	)
	(via
		(at 377.436634 -245.55069)
		(size 0.4572)
		(drill 0.2032)
		(layers "F.Cu" "B.Cu")
		(net "GND")
	)
	(via
		(at 300.21022 -417.990528)
		(size 0.508)
		(drill 0.254)
		(layers "F.Cu" "B.Cu")
		(net "GND")
	)
	(via
		(at 103.292148 -278.336502)
		(size 0.4572)
		(drill 0.2032)
		(layers "F.Cu" "B.Cu")
		(net "GND")
	)
	(via
		(at 46.964346 -311.216802)
		(size 0.4572)
		(drill 0.2032)
		(layers "F.Cu" "B.Cu")
		(net "GND")
	)
	(via
		(at 179.105814 -213.46668)
		(size 0.4572)
		(drill 0.2032)
		(layers "F.Cu" "B.Cu")
		(net "GND")
	)
	(via
		(at 159.918146 -281.466798)
		(size 0.4572)
		(drill 0.2032)
		(layers "F.Cu" "B.Cu")
		(net "GND")
	)
	(via
		(at 290.26866 -155.224988)
		(size 0.508)
		(drill 0.254)
		(layers "F.Cu" "B.Cu")
		(net "GND")
	)
	(via
		(at 422.945814 -238.966756)
		(size 0.4572)
		(drill 0.2032)
		(layers "F.Cu" "B.Cu")
		(net "GND")
	)
	(via
		(at 416.715702 -409.396184)
		(size 0.4572)
		(drill 0.254)
		(layers "F.Cu" "B.Cu")
		(net "GND")
	)
	(via
		(at 336.55508 -239.853216)
		(size 0.4572)
		(drill 0.2032)
		(layers "F.Cu" "B.Cu")
		(net "GND")
	)
	(via
		(at 300.238414 -197.316598)
		(size 0.4572)
		(drill 0.2032)
		(layers "F.Cu" "B.Cu")
		(net "GND")
	)
	(via
		(at 370.498116 -275.8948)
		(size 0.4572)
		(drill 0.2032)
		(layers "F.Cu" "B.Cu")
		(net "GND")
	)
	(via
		(at 316.035436 -400.224244)
		(size 0.4572)
		(drill 0.254)
		(layers "F.Cu" "B.Cu")
		(net "GND")
	)
	(via
		(at 176.896014 -198.166736)
		(size 0.4572)
		(drill 0.2032)
		(layers "F.Cu" "B.Cu")
		(net "GND")
	)
	(via
		(at 39.420546 -261.916672)
		(size 0.4572)
		(drill 0.2032)
		(layers "F.Cu" "B.Cu")
		(net "GND")
	)
	(via
		(at 363.919262 -266.128246)
		(size 0.4572)
		(drill 0.2032)
		(layers "F.Cu" "B.Cu")
		(net "GND")
	)
	(via
		(at 296.794682 -250.866656)
		(size 0.4572)
		(drill 0.2032)
		(layers "F.Cu" "B.Cu")
		(net "GND")
	)
	(via
		(at 196.030596 -42.549572)
		(size 0.508)
		(drill 0.254)
		(layers "F.Cu" "B.Cu")
		(net "GND")
	)
	(via
		(at 341.105998 -56.438546)
		(size 0.4572)
		(drill 0.2032)
		(layers "F.Cu" "B.Cu")
		(net "GND")
	)
	(via
		(at 134.259066 -340.904322)
		(size 0.508)
		(drill 0.254)
		(layers "F.Cu" "B.Cu")
		(net "GND")
	)
	(via
		(at 415.402014 -278.066754)
		(size 0.4572)
		(drill 0.2032)
		(layers "F.Cu" "B.Cu")
		(net "GND")
	)
	(via
		(at 286.353758 -413.63519)
		(size 0.508)
		(drill 0.254)
		(layers "F.Cu" "B.Cu")
		(net "GND")
	)
	(via
		(at 453.121014 -268.71676)
		(size 0.4572)
		(drill 0.2032)
		(layers "F.Cu" "B.Cu")
		(net "GND")
	)
	(via
		(at 354.521262 -272.639282)
		(size 0.4572)
		(drill 0.2032)
		(layers "F.Cu" "B.Cu")
		(net "GND")
	)
	(via
		(at 96.133412 -231.714548)
		(size 0.4572)
		(drill 0.2032)
		(layers "F.Cu" "B.Cu")
		(net "GND")
	)
	(via
		(at 341.80018 -401.492212)
		(size 0.4572)
		(drill 0.254)
		(layers "F.Cu" "B.Cu")
		(net "GND")
	)
	(via
		(at 319.25006 -436.347362)
		(size 0.4572)
		(drill 0.2032)
		(layers "F.Cu" "B.Cu")
		(net "GND")
	)
	(via
		(at 291.460682 -235.566712)
		(size 0.4572)
		(drill 0.2032)
		(layers "F.Cu" "B.Cu")
		(net "GND")
	)
	(via
		(at 401.019772 -16.967454)
		(size 0.508)
		(drill 0.254)
		(layers "F.Cu" "B.Cu")
		(net "GND")
	)
	(via
		(at 30.878018 -6.090412)
		(size 0.508)
		(drill 0.254)
		(layers "F.Cu" "B.Cu")
		(net "GND")
	)
	(via
		(at 307.782214 -246.616728)
		(size 0.4572)
		(drill 0.2032)
		(layers "F.Cu" "B.Cu")
		(net "GND")
	)
	(via
		(at 257.185414 -283.166566)
		(size 0.4572)
		(drill 0.2032)
		(layers "F.Cu" "B.Cu")
		(net "GND")
	)
	(via
		(at 438.033414 -298.466764)
		(size 0.4572)
		(drill 0.2032)
		(layers "F.Cu" "B.Cu")
		(net "GND")
	)
	(via
		(at 260.375908 -68.616068)
		(size 0.508)
		(drill 0.254)
		(layers "F.Cu" "B.Cu")
		(net "GND")
	)
	(via
		(at 52.191666 -406.370536)
		(size 0.4572)
		(drill 0.254)
		(layers "F.Cu" "B.Cu")
		(net "GND")
	)
	(via
		(at 370.85778 -239.0394)
		(size 0.4572)
		(drill 0.2032)
		(layers "F.Cu" "B.Cu")
		(net "GND")
	)
	(via
		(at 178.336448 -402.255482)
		(size 0.508)
		(drill 0.254)
		(layers "F.Cu" "B.Cu")
		(net "GND")
	)
	(via
		(at 83.54441 -336.982816)
		(size 0.508)
		(drill 0.254)
		(layers "F.Cu" "B.Cu")
		(net "GND")
	)
	(via
		(at 131.956048 -267.755878)
		(size 0.4572)
		(drill 0.2032)
		(layers "F.Cu" "B.Cu")
		(net "GND")
	)
	(via
		(at 375.196862 -279.150318)
		(size 0.4572)
		(drill 0.2032)
		(layers "F.Cu" "B.Cu")
		(net "GND")
	)
	(via
		(at 37.210746 -208.366614)
		(size 0.4572)
		(drill 0.2032)
		(layers "F.Cu" "B.Cu")
		(net "GND")
	)
	(via
		(at 462.555082 -207.51673)
		(size 0.4572)
		(drill 0.2032)
		(layers "F.Cu" "B.Cu")
		(net "GND")
	)
	(via
		(at 387.887718 -407.638504)
		(size 0.4572)
		(drill 0.254)
		(layers "F.Cu" "B.Cu")
		(net "GND")
	)
	(via
		(at 307.782214 -229.616762)
		(size 0.4572)
		(drill 0.2032)
		(layers "F.Cu" "B.Cu")
		(net "GND")
	)
	(via
		(at 212.724746 -285.716726)
		(size 0.4572)
		(drill 0.2032)
		(layers "F.Cu" "B.Cu")
		(net "GND")
	)
	(via
		(at 90.604848 -287.28924)
		(size 0.4572)
		(drill 0.2032)
		(layers "F.Cu" "B.Cu")
		(net "GND")
	)
	(via
		(at 458.399642 -68.487036)
		(size 0.508)
		(drill 0.254)
		(layers "F.Cu" "B.Cu")
		(net "GND")
	)
	(via
		(at 253.389892 -97.269808)
		(size 0.508)
		(drill 0.254)
		(layers "F.Cu" "B.Cu")
		(net "GND")
	)
	(via
		(at 124.907548 -283.219906)
		(size 0.4572)
		(drill 0.2032)
		(layers "F.Cu" "B.Cu")
		(net "GND")
	)
	(via
		(at 202.971146 -260.21665)
		(size 0.4572)
		(drill 0.2032)
		(layers "F.Cu" "B.Cu")
		(net "GND")
	)
	(via
		(at 379.956822 -409.396184)
		(size 0.4572)
		(drill 0.254)
		(layers "F.Cu" "B.Cu")
		(net "GND")
	)
	(via
		(at 197.637146 -279.766776)
		(size 0.4572)
		(drill 0.2032)
		(layers "F.Cu" "B.Cu")
		(net "GND")
	)
	(via
		(at 18.679414 -261.066788)
		(size 0.4572)
		(drill 0.2032)
		(layers "F.Cu" "B.Cu")
		(net "GND")
	)
	(via
		(at 103.618792 -292.95598)
		(size 0.508)
		(drill 0.254)
		(layers "F.Cu" "B.Cu")
		(net "GND")
	)
	(via
		(at 44.754546 -225.36658)
		(size 0.4572)
		(drill 0.2032)
		(layers "F.Cu" "B.Cu")
		(net "GND")
	)
	(via
		(at 285.150814 -233.016806)
		(size 0.4572)
		(drill 0.2032)
		(layers "F.Cu" "B.Cu")
		(net "GND")
	)
	(via
		(at 52.298346 -315.46673)
		(size 0.4572)
		(drill 0.2032)
		(layers "F.Cu" "B.Cu")
		(net "GND")
	)
	(via
		(at 212.376004 -15.920974)
		(size 0.508)
		(drill 0.254)
		(layers "F.Cu" "B.Cu")
		(net "GND")
	)
	(via
		(at 329.25004 -439.651394)
		(size 0.4572)
		(drill 0.2032)
		(layers "F.Cu" "B.Cu")
		(net "GND")
	)
	(via
		(at 382.135634 -239.0394)
		(size 0.4572)
		(drill 0.2032)
		(layers "F.Cu" "B.Cu")
		(net "GND")
	)
	(via
		(at 340.894416 -268.569694)
		(size 0.4572)
		(drill 0.2032)
		(layers "F.Cu" "B.Cu")
		(net "GND")
	)
	(via
		(at 195.427346 -234.716574)
		(size 0.4572)
		(drill 0.2032)
		(layers "F.Cu" "B.Cu")
		(net "GND")
	)
	(via
		(at 202.971146 -216.016586)
		(size 0.4572)
		(drill 0.2032)
		(layers "F.Cu" "B.Cu")
		(net "GND")
	)
	(via
		(at 63.250064 -437.49976)
		(size 0.4572)
		(drill 0.2032)
		(layers "F.Cu" "B.Cu")
		(net "GND")
	)
	(via
		(at 457.221082 -228.766624)
		(size 0.4572)
		(drill 0.2032)
		(layers "F.Cu" "B.Cu")
		(net "GND")
	)
	(via
		(at 419.502082 -226.216718)
		(size 0.4572)
		(drill 0.2032)
		(layers "F.Cu" "B.Cu")
		(net "GND")
	)
	(via
		(at 344.25001 -431.451258)
		(size 0.4572)
		(drill 0.2032)
		(layers "F.Cu" "B.Cu")
		(net "GND")
	)
	(via
		(at 235.491782 -48.104044)
		(size 0.508)
		(drill 0.254)
		(layers "F.Cu" "B.Cu")
		(net "GND")
	)
	(via
		(at 464.572604 -93.396054)
		(size 0.508)
		(drill 0.254)
		(layers "F.Cu" "B.Cu")
		(net "GND")
	)
	(via
		(at 349.24238 -239.0394)
		(size 0.4572)
		(drill 0.2032)
		(layers "F.Cu" "B.Cu")
		(net "GND")
	)
	(via
		(at 339.954616 -279.964134)
		(size 0.4572)
		(drill 0.2032)
		(layers "F.Cu" "B.Cu")
		(net "GND")
	)
	(via
		(at 348.549722 -180.113432)
		(size 0.508)
		(drill 0.254)
		(layers "F.Cu" "B.Cu")
		(net "GND")
	)
	(via
		(at 126.786894 -286.475424)
		(size 0.4572)
		(drill 0.2032)
		(layers "F.Cu" "B.Cu")
		(net "GND")
	)
	(via
		(at 400.140678 -407.638504)
		(size 0.4572)
		(drill 0.254)
		(layers "F.Cu" "B.Cu")
		(net "GND")
	)
	(via
		(at 341.254334 -223.575626)
		(size 0.4572)
		(drill 0.2032)
		(layers "F.Cu" "B.Cu")
		(net "GND")
	)
	(via
		(at 452.20128 -45.110908)
		(size 0.508)
		(drill 0.254)
		(layers "F.Cu" "B.Cu")
		(net "GND")
	)
	(via
		(at 350.762062 -271.011396)
		(size 0.4572)
		(drill 0.2032)
		(layers "F.Cu" "B.Cu")
		(net "GND")
	)
	(via
		(at 56.398414 -204.116686)
		(size 0.4572)
		(drill 0.2032)
		(layers "F.Cu" "B.Cu")
		(net "GND")
	)
	(via
		(at 338.434934 -249.620024)
		(size 0.4572)
		(drill 0.2032)
		(layers "F.Cu" "B.Cu")
		(net "GND")
	)
	(via
		(at 388.349998 -428.851314)
		(size 0.4572)
		(drill 0.2032)
		(layers "F.Cu" "B.Cu")
		(net "GND")
	)
	(via
		(at 370.388134 -231.714548)
		(size 0.4572)
		(drill 0.2032)
		(layers "F.Cu" "B.Cu")
		(net "GND")
	)
	(via
		(at 300.238414 -281.466798)
		(size 0.4572)
		(drill 0.2032)
		(layers "F.Cu" "B.Cu")
		(net "GND")
	)
	(via
		(at 276.373082 -264.466578)
		(size 0.4572)
		(drill 0.2032)
		(layers "F.Cu" "B.Cu")
		(net "GND")
	)
	(via
		(at 453.121014 -304.416714)
		(size 0.4572)
		(drill 0.2032)
		(layers "F.Cu" "B.Cu")
		(net "GND")
	)
	(via
		(at 186.649614 -305.266598)
		(size 0.4572)
		(drill 0.2032)
		(layers "F.Cu" "B.Cu")
		(net "GND")
	)
	(via
		(at 422.945814 -281.466798)
		(size 0.4572)
		(drill 0.2032)
		(layers "F.Cu" "B.Cu")
		(net "GND")
	)
	(via
		(at 237.615984 -53.364892)
		(size 0.508)
		(drill 0.254)
		(layers "F.Cu" "B.Cu")
		(net "GND")
	)
	(via
		(at 135.605266 -221.94774)
		(size 0.4572)
		(drill 0.2032)
		(layers "F.Cu" "B.Cu")
		(net "GND")
	)
	(via
		(at 411.958282 -204.116686)
		(size 0.4572)
		(drill 0.2032)
		(layers "F.Cu" "B.Cu")
		(net "GND")
	)
	(via
		(at 447.467482 -303.566576)
		(size 0.4572)
		(drill 0.2032)
		(layers "F.Cu" "B.Cu")
		(net "GND")
	)
	(via
		(at 129.026666 -246.364506)
		(size 0.4572)
		(drill 0.2032)
		(layers "F.Cu" "B.Cu")
		(net "GND")
	)
	(via
		(at 268.886686 -12.544552)
		(size 0.508)
		(drill 0.254)
		(layers "F.Cu" "B.Cu")
		(net "GND")
	)
	(via
		(at 114.154458 -201.48677)
		(size 0.6604)
		(drill 0.3302)
		(layers "F.Cu" "B.Cu")
		(net "GND")
	)
	(via
		(at 461.993996 -107.678728)
		(size 0.508)
		(drill 0.254)
		(layers "F.Cu" "B.Cu")
		(net "GND")
	)
	(via
		(at 67.250056 -430.299622)
		(size 0.4572)
		(drill 0.2032)
		(layers "F.Cu" "B.Cu")
		(net "GND")
	)
	(via
		(at 314.092082 -301.01667)
		(size 0.4572)
		(drill 0.2032)
		(layers "F.Cu" "B.Cu")
		(net "GND")
	)
	(via
		(at 35.976814 -278.916638)
		(size 0.4572)
		(drill 0.2032)
		(layers "F.Cu" "B.Cu")
		(net "GND")
	)
	(via
		(at 407.62301 -403.883876)
		(size 0.4064)
		(drill 0.2032)
		(layers "F.Cu" "B.Cu")
		(net "GND")
	)
	(via
		(at 363.80928 -233.34218)
		(size 0.4572)
		(drill 0.2032)
		(layers "F.Cu" "B.Cu")
		(net "GND")
	)
	(via
		(at 84.495894 -265.314176)
		(size 0.4572)
		(drill 0.2032)
		(layers "F.Cu" "B.Cu")
		(net "GND")
	)
	(via
		(at 167.064436 -134.17677)
		(size 0.508)
		(drill 0.254)
		(layers "F.Cu" "B.Cu")
		(net "GND")
	)
	(via
		(at 96.133666 -247.992138)
		(size 0.4572)
		(drill 0.2032)
		(layers "F.Cu" "B.Cu")
		(net "GND")
	)
	(via
		(at 108.820966 -222.761556)
		(size 0.4572)
		(drill 0.2032)
		(layers "F.Cu" "B.Cu")
		(net "GND")
	)
	(via
		(at 299.004482 -297.616626)
		(size 0.4572)
		(drill 0.2032)
		(layers "F.Cu" "B.Cu")
		(net "GND")
	)
	(via
		(at 455.011282 -211.766658)
		(size 0.4572)
		(drill 0.2032)
		(layers "F.Cu" "B.Cu")
		(net "GND")
	)
	(via
		(at 216.824814 -219.41663)
		(size 0.4572)
		(drill 0.2032)
		(layers "F.Cu" "B.Cu")
		(net "GND")
	)
	(via
		(at 345.123262 -284.033722)
		(size 0.4572)
		(drill 0.2032)
		(layers "F.Cu" "B.Cu")
		(net "GND")
	)
	(via
		(at 339.844634 -216.25052)
		(size 0.4572)
		(drill 0.2032)
		(layers "F.Cu" "B.Cu")
		(net "GND")
	)
	(via
		(at 380.256034 -222.761556)
		(size 0.4572)
		(drill 0.2032)
		(layers "F.Cu" "B.Cu")
		(net "GND")
	)
	(via
		(at 274.163282 -314.616592)
		(size 0.4572)
		(drill 0.2032)
		(layers "F.Cu" "B.Cu")
		(net "GND")
	)
	(via
		(at 438.033414 -300.166786)
		(size 0.4572)
		(drill 0.2032)
		(layers "F.Cu" "B.Cu")
		(net "GND")
	)
	(via
		(at 237.615984 -58.764932)
		(size 0.508)
		(drill 0.254)
		(layers "F.Cu" "B.Cu")
		(net "GND")
	)
	(via
		(at 266.619482 -264.466578)
		(size 0.4572)
		(drill 0.2032)
		(layers "F.Cu" "B.Cu")
		(net "GND")
	)
	(via
		(at 433.352448 -18.491454)
		(size 0.508)
		(drill 0.254)
		(layers "F.Cu" "B.Cu")
		(net "GND")
	)
	(via
		(at 310.207914 -311.216802)
		(size 0.4572)
		(drill 0.2032)
		(layers "F.Cu" "B.Cu")
		(net "GND")
	)
	(via
		(at 329.25004 -426.54728)
		(size 0.4572)
		(drill 0.2032)
		(layers "F.Cu" "B.Cu")
		(net "GND")
	)
	(via
		(at 28.433014 -245.76659)
		(size 0.4572)
		(drill 0.2032)
		(layers "F.Cu" "B.Cu")
		(net "GND")
	)
	(via
		(at 300.238414 -309.51678)
		(size 0.4572)
		(drill 0.2032)
		(layers "F.Cu" "B.Cu")
		(net "GND")
	)
	(via
		(at 186.649614 -269.566644)
		(size 0.4572)
		(drill 0.2032)
		(layers "F.Cu" "B.Cu")
		(net "GND")
	)
	(via
		(at 200.20915 -352.725482)
		(size 0.508)
		(drill 0.254)
		(layers "F.Cu" "B.Cu")
		(net "GND")
	)
	(via
		(at 442.133482 -211.766658)
		(size 0.4572)
		(drill 0.2032)
		(layers "F.Cu" "B.Cu")
		(net "GND")
	)
	(via
		(at 135.273542 -401.492212)
		(size 0.4572)
		(drill 0.254)
		(layers "F.Cu" "B.Cu")
		(net "GND")
	)
	(via
		(at 424.836082 -280.61666)
		(size 0.4572)
		(drill 0.2032)
		(layers "F.Cu" "B.Cu")
		(net "GND")
	)
	(via
		(at 448.084448 -178.802792)
		(size 0.508)
		(drill 0.254)
		(layers "F.Cu" "B.Cu")
		(net "GND")
	)
	(via
		(at 103.14559 -332.56601)
		(size 0.49022)
		(drill 0.254)
		(layers "F.Cu" "B.Cu")
		(net "GND")
	)
	(via
		(at 115.428522 -255.805686)
		(size 0.4572)
		(drill 0.2032)
		(layers "F.Cu" "B.Cu")
		(net "GND")
	)
	(via
		(at 56.398414 -282.316682)
		(size 0.4572)
		(drill 0.2032)
		(layers "F.Cu" "B.Cu")
		(net "GND")
	)
	(via
		(at 102.242366 -219.506038)
		(size 0.4572)
		(drill 0.2032)
		(layers "F.Cu" "B.Cu")
		(net "GND")
	)
	(via
		(at 456.765406 -78.402434)
		(size 0.508)
		(drill 0.254)
		(layers "F.Cu" "B.Cu")
		(net "GND")
	)
	(via
		(at 63.250064 -426.69968)
		(size 0.4572)
		(drill 0.2032)
		(layers "F.Cu" "B.Cu")
		(net "GND")
	)
	(via
		(at 464.764882 -235.566712)
		(size 0.4572)
		(drill 0.2032)
		(layers "F.Cu" "B.Cu")
		(net "GND")
	)
	(via
		(at 94.254066 -246.364506)
		(size 0.4572)
		(drill 0.2032)
		(layers "F.Cu" "B.Cu")
		(net "GND")
	)
	(via
		(at 123.027948 -266.941808)
		(size 0.4572)
		(drill 0.2032)
		(layers "F.Cu" "B.Cu")
		(net "GND")
	)
	(via
		(at 162.49523 -435.447948)
		(size 0.508)
		(drill 0.254)
		(layers "F.Cu" "B.Cu")
		(net "GND")
	)
	(via
		(at 458.455014 -238.966756)
		(size 0.4572)
		(drill 0.2032)
		(layers "F.Cu" "B.Cu")
		(net "GND")
	)
	(via
		(at 374.617234 -242.294918)
		(size 0.4572)
		(drill 0.2032)
		(layers "F.Cu" "B.Cu")
		(net "GND")
	)
	(via
		(at 277.607014 -225.36658)
		(size 0.4572)
		(drill 0.2032)
		(layers "F.Cu" "B.Cu")
		(net "GND")
	)
	(via
		(at 442.133482 -249.166634)
		(size 0.4572)
		(drill 0.2032)
		(layers "F.Cu" "B.Cu")
		(net "GND")
	)
	(via
		(at 29.666946 -258.516628)
		(size 0.4572)
		(drill 0.2032)
		(layers "F.Cu" "B.Cu")
		(net "GND")
	)
	(via
		(at 428.279814 -250.016772)
		(size 0.4572)
		(drill 0.2032)
		(layers "F.Cu" "B.Cu")
		(net "GND")
	)
	(via
		(at 100.832666 -231.714548)
		(size 0.4572)
		(drill 0.2032)
		(layers "F.Cu" "B.Cu")
		(net "GND")
	)
	(via
		(at 309.992014 -212.616796)
		(size 0.4572)
		(drill 0.2032)
		(layers "F.Cu" "B.Cu")
		(net "GND")
	)
	(via
		(at 387.800342 -403.249892)
		(size 0.4572)
		(drill 0.254)
		(layers "F.Cu" "B.Cu")
		(net "GND")
	)
	(via
		(at 302.448214 -317.166752)
		(size 0.4572)
		(drill 0.2032)
		(layers "F.Cu" "B.Cu")
		(net "GND")
	)
	(via
		(at 157.48127 -216.016586)
		(size 0.4572)
		(drill 0.2032)
		(layers "F.Cu" "B.Cu")
		(net "GND")
	)
	(via
		(at 460.0575 -388.06882)
		(size 0.508)
		(drill 0.254)
		(layers "F.Cu" "B.Cu")
		(net "GND")
	)
	(via
		(at 410.68625 -403.883876)
		(size 0.4064)
		(drill 0.2032)
		(layers "F.Cu" "B.Cu")
		(net "GND")
	)
	(via
		(at 133.835394 -280.778204)
		(size 0.4572)
		(drill 0.2032)
		(layers "F.Cu" "B.Cu")
		(net "GND")
	)
	(via
		(at 418.089588 -16.967454)
		(size 0.508)
		(drill 0.254)
		(layers "F.Cu" "B.Cu")
		(net "GND")
	)
	(via
		(at 359.580434 -226.017328)
		(size 0.4572)
		(drill 0.2032)
		(layers "F.Cu" "B.Cu")
		(net "GND")
	)
	(via
		(at 95.33382 -30.780228)
		(size 0.508)
		(drill 0.254)
		(layers "F.Cu" "B.Cu")
		(net "GND")
	)
	(via
		(at 160.3502 -42.639488)
		(size 0.508)
		(drill 0.254)
		(layers "F.Cu" "B.Cu")
		(net "GND")
	)
	(via
		(at 396.418562 -6.586474)
		(size 0.508)
		(drill 0.254)
		(layers "F.Cu" "B.Cu")
		(net "GND")
	)
	(via
		(at 150.492714 -407.00452)
		(size 0.4064)
		(drill 0.2032)
		(layers "F.Cu" "B.Cu")
		(net "GND")
	)
	(via
		(at 367.678462 -280.778204)
		(size 0.4572)
		(drill 0.2032)
		(layers "F.Cu" "B.Cu")
		(net "GND")
	)
	(via
		(at 172.795946 -234.716574)
		(size 0.4572)
		(drill 0.2032)
		(layers "F.Cu" "B.Cu")
		(net "GND")
	)
	(via
		(at 365.329216 -266.941808)
		(size 0.4572)
		(drill 0.2032)
		(layers "F.Cu" "B.Cu")
		(net "GND")
	)
	(via
		(at 315.57722 -406.370536)
		(size 0.4572)
		(drill 0.254)
		(layers "F.Cu" "B.Cu")
		(net "GND")
	)
	(via
		(at 37.210746 -223.666558)
		(size 0.4572)
		(drill 0.2032)
		(layers "F.Cu" "B.Cu")
		(net "GND")
	)
	(via
		(at 20.889214 -314.616592)
		(size 0.4572)
		(drill 0.2032)
		(layers "F.Cu" "B.Cu")
		(net "GND")
	)
	(via
		(at 185.875676 -350.922082)
		(size 0.508)
		(drill 0.254)
		(layers "F.Cu" "B.Cu")
		(net "GND")
	)
	(via
		(at 346.532962 -260.430772)
		(size 0.4572)
		(drill 0.2032)
		(layers "F.Cu" "B.Cu")
		(net "GND")
	)
	(via
		(at 289.250882 -202.416664)
		(size 0.4572)
		(drill 0.2032)
		(layers "F.Cu" "B.Cu")
		(net "GND")
	)
	(via
		(at 412.84398 -158.435548)
		(size 0.508)
		(drill 0.254)
		(layers "F.Cu" "B.Cu")
		(net "GND")
	)
	(via
		(at 2.764536 -208.710022)
		(size 0.508)
		(drill 0.254)
		(layers "F.Cu" "B.Cu")
		(net "GND")
	)
	(via
		(at 370.860828 -331.776832)
		(size 0.49022)
		(drill 0.254)
		(layers "F.Cu" "B.Cu")
		(net "GND")
	)
	(via
		(at 419.81374 -103.480108)
		(size 0.508)
		(drill 0.254)
		(layers "F.Cu" "B.Cu")
		(net "GND")
	)
	(via
		(at 265.723624 -112.445546)
		(size 0.508)
		(drill 0.254)
		(layers "F.Cu" "B.Cu")
		(net "GND")
	)
	(via
		(at 66.00063 -117.123718)
		(size 0.508)
		(drill 0.254)
		(layers "F.Cu" "B.Cu")
		(net "GND")
	)
	(via
		(at 380.725934 -223.575626)
		(size 0.4572)
		(drill 0.2032)
		(layers "F.Cu" "B.Cu")
		(net "GND")
	)
	(via
		(at 62.051946 -270.416782)
		(size 0.4572)
		(drill 0.2032)
		(layers "F.Cu" "B.Cu")
		(net "GND")
	)
	(via
		(at 467.535514 -388.48538)
		(size 0.508)
		(drill 0.254)
		(layers "F.Cu" "B.Cu")
		(net "GND")
	)
	(via
		(at 51.064414 -244.066568)
		(size 0.4572)
		(drill 0.2032)
		(layers "F.Cu" "B.Cu")
		(net "GND")
	)
	(via
		(at 172.795946 -233.016806)
		(size 0.4572)
		(drill 0.2032)
		(layers "F.Cu" "B.Cu")
		(net "GND")
	)
	(via
		(at 140.349986 -437.34736)
		(size 0.4572)
		(drill 0.2032)
		(layers "F.Cu" "B.Cu")
		(net "GND")
	)
	(via
		(at 113.338102 -333.355188)
		(size 0.49022)
		(drill 0.254)
		(layers "F.Cu" "B.Cu")
		(net "GND")
	)
	(via
		(at 153.34996 -439.651394)
		(size 0.4572)
		(drill 0.2032)
		(layers "F.Cu" "B.Cu")
		(net "GND")
	)
	(via
		(at 127.726948 -271.825212)
		(size 0.4572)
		(drill 0.2032)
		(layers "F.Cu" "B.Cu")
		(net "GND")
	)
	(via
		(at 455.437494 -6.263386)
		(size 0.508)
		(drill 0.254)
		(layers "F.Cu" "B.Cu")
		(net "GND")
	)
	(via
		(at 434.589682 -207.51673)
		(size 0.4572)
		(drill 0.2032)
		(layers "F.Cu" "B.Cu")
		(net "GND")
	)
	(via
		(at 26.223214 -202.416664)
		(size 0.4572)
		(drill 0.2032)
		(layers "F.Cu" "B.Cu")
		(net "GND")
	)
	(via
		(at 272.273014 -309.51678)
		(size 0.4572)
		(drill 0.2032)
		(layers "F.Cu" "B.Cu")
		(net "GND")
	)
	(via
		(at 369.558062 -287.28924)
		(size 0.4572)
		(drill 0.2032)
		(layers "F.Cu" "B.Cu")
		(net "GND")
	)
	(via
		(at 126.098554 -332.47203)
		(size 0.508)
		(drill 0.254)
		(layers "F.Cu" "B.Cu")
		(net "GND")
	)
	(via
		(at 268.829282 -241.516662)
		(size 0.4572)
		(drill 0.2032)
		(layers "F.Cu" "B.Cu")
		(net "GND")
	)
	(via
		(at 300.022514 -236.416596)
		(size 0.4572)
		(drill 0.2032)
		(layers "F.Cu" "B.Cu")
		(net "GND")
	)
	(via
		(at 61.212222 -159.56788)
		(size 0.508)
		(drill 0.254)
		(layers "F.Cu" "B.Cu")
		(net "GND")
	)
	(via
		(at 374.288558 -403.249892)
		(size 0.4572)
		(drill 0.254)
		(layers "F.Cu" "B.Cu")
		(net "GND")
	)
	(via
		(at 78.664054 -340.977728)
		(size 0.49022)
		(drill 0.254)
		(layers "F.Cu" "B.Cu")
		(net "GND")
	)
	(via
		(at 269.234412 -69.91985)
		(size 0.6604)
		(drill 0.3302)
		(layers "F.Cu" "B.Cu")
		(net "GND")
	)
	(via
		(at 261.285482 -262.76681)
		(size 0.4572)
		(drill 0.2032)
		(layers "F.Cu" "B.Cu")
		(net "GND")
	)
	(via
		(at 54.724046 -276.366732)
		(size 0.4572)
		(drill 0.2032)
		(layers "F.Cu" "B.Cu")
		(net "GND")
	)
	(via
		(at 340.305136 -331.852524)
		(size 0.508)
		(drill 0.254)
		(layers "F.Cu" "B.Cu")
		(net "GND")
	)
	(via
		(at 191.983614 -301.01667)
		(size 0.4572)
		(drill 0.2032)
		(layers "F.Cu" "B.Cu")
		(net "GND")
	)
	(via
		(at 386.350002 -431.451258)
		(size 0.4572)
		(drill 0.2032)
		(layers "F.Cu" "B.Cu")
		(net "GND")
	)
	(via
		(at 181.455822 -354.115878)
		(size 0.49022)
		(drill 0.254)
		(layers "F.Cu" "B.Cu")
		(net "GND")
	)
	(via
		(at 443.367414 -208.366614)
		(size 0.4572)
		(drill 0.2032)
		(layers "F.Cu" "B.Cu")
		(net "GND")
	)
	(via
		(at 197.637146 -298.466764)
		(size 0.4572)
		(drill 0.2032)
		(layers "F.Cu" "B.Cu")
		(net "GND")
	)
	(via
		(at 283.916882 -230.466646)
		(size 0.4572)
		(drill 0.2032)
		(layers "F.Cu" "B.Cu")
		(net "GND")
	)
	(via
		(at 448.084448 -180.910992)
		(size 0.508)
		(drill 0.254)
		(layers "F.Cu" "B.Cu")
		(net "GND")
	)
	(via
		(at 449.677282 -210.066636)
		(size 0.4572)
		(drill 0.2032)
		(layers "F.Cu" "B.Cu")
		(net "GND")
	)
	(via
		(at 167.715946 -220.266768)
		(size 0.4572)
		(drill 0.2032)
		(layers "F.Cu" "B.Cu")
		(net "GND")
	)
	(via
		(at 86.10219 -58.295286)
		(size 0.508)
		(drill 0.254)
		(layers "F.Cu" "B.Cu")
		(net "GND")
	)
	(via
		(at 104.62514 -413.80918)
		(size 0.508)
		(drill 0.254)
		(layers "F.Cu" "B.Cu")
		(net "GND")
	)
	(via
		(at 387.304534 -231.714548)
		(size 0.4572)
		(drill 0.2032)
		(layers "F.Cu" "B.Cu")
		(net "GND")
	)
	(via
		(at 105.061766 -219.506038)
		(size 0.4572)
		(drill 0.2032)
		(layers "F.Cu" "B.Cu")
		(net "GND")
	)
	(via
		(at 125.377448 -272.639282)
		(size 0.4572)
		(drill 0.2032)
		(layers "F.Cu" "B.Cu")
		(net "GND")
	)
	(via
		(at 56.398414 -295.916604)
		(size 0.4572)
		(drill 0.2032)
		(layers "F.Cu" "B.Cu")
		(net "GND")
	)
	(via
		(at 26.223214 -264.466578)
		(size 0.4572)
		(drill 0.2032)
		(layers "F.Cu" "B.Cu")
		(net "GND")
	)
	(via
		(at 169.352214 -249.166634)
		(size 0.4572)
		(drill 0.2032)
		(layers "F.Cu" "B.Cu")
		(net "GND")
	)
	(via
		(at 195.427346 -307.816758)
		(size 0.4572)
		(drill 0.2032)
		(layers "F.Cu" "B.Cu")
		(net "GND")
	)
	(via
		(at 119.268748 -278.336502)
		(size 0.4572)
		(drill 0.2032)
		(layers "F.Cu" "B.Cu")
		(net "GND")
	)
	(via
		(at 346.063062 -284.033722)
		(size 0.4572)
		(drill 0.2032)
		(layers "F.Cu" "B.Cu")
		(net "GND")
	)
	(via
		(at 205.180946 -265.316716)
		(size 0.4572)
		(drill 0.2032)
		(layers "F.Cu" "B.Cu")
		(net "GND")
	)
	(via
		(at 131.955794 -282.405836)
		(size 0.4572)
		(drill 0.2032)
		(layers "F.Cu" "B.Cu")
		(net "GND")
	)
	(via
		(at 388.349998 -437.34736)
		(size 0.4572)
		(drill 0.2032)
		(layers "F.Cu" "B.Cu")
		(net "GND")
	)
	(via
		(at 127.342646 -403.249892)
		(size 0.4572)
		(drill 0.254)
		(layers "F.Cu" "B.Cu")
		(net "GND")
	)
	(via
		(at 176.955704 -115.775486)
		(size 0.4572)
		(drill 0.254)
		(layers "F.Cu" "B.Cu")
		(net "GND")
	)
	(via
		(at 179.494942 -31.181548)
		(size 0.508)
		(drill 0.254)
		(layers "F.Cu" "B.Cu")
		(net "GND")
	)
	(via
		(at 169.149014 -294.216582)
		(size 0.4572)
		(drill 0.2032)
		(layers "F.Cu" "B.Cu")
		(net "GND")
	)
	(via
		(at 172.343318 -345.64701)
		(size 0.508)
		(drill 0.254)
		(layers "F.Cu" "B.Cu")
		(net "GND")
	)
	(via
		(at 7.035546 -273.816572)
		(size 0.4572)
		(drill 0.2032)
		(layers "F.Cu" "B.Cu")
		(net "GND")
	)
	(via
		(at 432.379882 -250.866656)
		(size 0.4572)
		(drill 0.2032)
		(layers "F.Cu" "B.Cu")
		(net "GND")
	)
	(via
		(at 319.223898 -190.39967)
		(size 0.508)
		(drill 0.254)
		(layers "F.Cu" "B.Cu")
		(net "GND")
	)
	(via
		(at 389.0645 -50.739548)
		(size 0.508)
		(drill 0.254)
		(layers "F.Cu" "B.Cu")
		(net "GND")
	)
	(via
		(at 314.07608 -54.219348)
		(size 0.508)
		(drill 0.254)
		(layers "F.Cu" "B.Cu")
		(net "GND")
	)
	(via
		(at 24.332946 -301.866808)
		(size 0.4572)
		(drill 0.2032)
		(layers "F.Cu" "B.Cu")
		(net "GND")
	)
	(via
		(at 443.367414 -246.616728)
		(size 0.4572)
		(drill 0.2032)
		(layers "F.Cu" "B.Cu")
		(net "GND")
	)
	(via
		(at 262.519414 -208.366614)
		(size 0.4572)
		(drill 0.2032)
		(layers "F.Cu" "B.Cu")
		(net "GND")
	)
	(via
		(at 103.182166 -222.761556)
		(size 0.4572)
		(drill 0.2032)
		(layers "F.Cu" "B.Cu")
		(net "GND")
	)
	(via
		(at 153.34996 -434.899562)
		(size 0.4572)
		(drill 0.2032)
		(layers "F.Cu" "B.Cu")
		(net "GND")
	)
	(via
		(at 151.531574 -46.951646)
		(size 0.508)
		(drill 0.254)
		(layers "F.Cu" "B.Cu")
		(net "GND")
	)
	(via
		(at 87.785194 -288.917126)
		(size 0.4572)
		(drill 0.2032)
		(layers "F.Cu" "B.Cu")
		(net "GND")
	)
	(via
		(at 33.75533 -441.225432)
		(size 0.508)
		(drill 0.254)
		(layers "F.Cu" "B.Cu")
		(net "GND")
	)
	(via
		(at 428.03826 -360.94162)
		(size 0.49022)
		(drill 0.254)
		(layers "F.Cu" "B.Cu")
		(net "GND")
	)
	(via
		(at 329.155298 -80.155034)
		(size 0.508)
		(drill 0.254)
		(layers "F.Cu" "B.Cu")
		(net "GND")
	)
	(via
		(at 447.467482 -244.066568)
		(size 0.4572)
		(drill 0.2032)
		(layers "F.Cu" "B.Cu")
		(net "GND")
	)
	(via
		(at 450.911214 -238.966756)
		(size 0.4572)
		(drill 0.2032)
		(layers "F.Cu" "B.Cu")
		(net "GND")
	)
	(via
		(at 305.08194 -427.168818)
		(size 0.508)
		(drill 0.254)
		(layers "F.Cu" "B.Cu")
		(net "GND")
	)
	(via
		(at 342.735154 -54.558692)
		(size 0.4572)
		(drill 0.2032)
		(layers "F.Cu" "B.Cu")
		(net "GND")
	)
	(via
		(at 100.832412 -243.108988)
		(size 0.4572)
		(drill 0.2032)
		(layers "F.Cu" "B.Cu")
		(net "GND")
	)
	(via
		(at 237.615984 -51.565048)
		(size 0.508)
		(drill 0.254)
		(layers "F.Cu" "B.Cu")
		(net "GND")
	)
	(via
		(at 51.064414 -261.066788)
		(size 0.4572)
		(drill 0.2032)
		(layers "F.Cu" "B.Cu")
		(net "GND")
	)
	(via
		(at 361.012232 -335.704434)
		(size 0.49022)
		(drill 0.254)
		(layers "F.Cu" "B.Cu")
		(net "GND")
	)
	(via
		(at 342.737948 -71.92137)
		(size 0.508)
		(drill 0.254)
		(layers "F.Cu" "B.Cu")
		(net "GND")
	)
	(via
		(at 424.836082 -312.91657)
		(size 0.4572)
		(drill 0.2032)
		(layers "F.Cu" "B.Cu")
		(net "GND")
	)
	(via
		(at 285.150814 -307.816758)
		(size 0.4572)
		(drill 0.2032)
		(layers "F.Cu" "B.Cu")
		(net "GND")
	)
	(via
		(at 124.797566 -226.017328)
		(size 0.4572)
		(drill 0.2032)
		(layers "F.Cu" "B.Cu")
		(net "GND")
	)
	(via
		(at 201.737214 -301.01667)
		(size 0.4572)
		(drill 0.2032)
		(layers "F.Cu" "B.Cu")
		(net "GND")
	)
	(via
		(at 121.148348 -279.964134)
		(size 0.4572)
		(drill 0.2032)
		(layers "F.Cu" "B.Cu")
		(net "GND")
	)
	(via
		(at 294.904414 -289.11677)
		(size 0.4572)
		(drill 0.2032)
		(layers "F.Cu" "B.Cu")
		(net "GND")
	)
	(via
		(at 22.123146 -223.666558)
		(size 0.4572)
		(drill 0.2032)
		(layers "F.Cu" "B.Cu")
		(net "GND")
	)
	(via
		(at 37.210746 -227.066602)
		(size 0.4572)
		(drill 0.2032)
		(layers "F.Cu" "B.Cu")
		(net "GND")
	)
	(via
		(at 118.328948 -284.847538)
		(size 0.4572)
		(drill 0.2032)
		(layers "F.Cu" "B.Cu")
		(net "GND")
	)
	(via
		(at 163.257484 -323.434456)
		(size 0.4572)
		(drill 0.2032)
		(layers "F.Cu" "B.Cu")
		(net "GND")
	)
	(via
		(at 54.508146 -216.016586)
		(size 0.4572)
		(drill 0.2032)
		(layers "F.Cu" "B.Cu")
		(net "GND")
	)
	(via
		(at 86.250018 -428.851314)
		(size 0.4572)
		(drill 0.2032)
		(layers "F.Cu" "B.Cu")
		(net "GND")
	)
	(via
		(at 417.173918 -401.492212)
		(size 0.4572)
		(drill 0.254)
		(layers "F.Cu" "B.Cu")
		(net "GND")
	)
	(via
		(at 386.385054 -54.749954)
		(size 0.508)
		(drill 0.254)
		(layers "F.Cu" "B.Cu")
		(net "GND")
	)
	(via
		(at 195.427346 -199.01662)
		(size 0.4572)
		(drill 0.2032)
		(layers "F.Cu" "B.Cu")
		(net "GND")
	)
	(via
		(at 379.68936 -330.313538)
		(size 0.508)
		(drill 0.254)
		(layers "F.Cu" "B.Cu")
		(net "GND")
	)
	(via
		(at 341.254334 -220.319854)
		(size 0.4572)
		(drill 0.2032)
		(layers "F.Cu" "B.Cu")
		(net "GND")
	)
	(via
		(at 100.362766 -216.25052)
		(size 0.4572)
		(drill 0.2032)
		(layers "F.Cu" "B.Cu")
		(net "GND")
	)
	(via
		(at 122.557794 -284.033722)
		(size 0.4572)
		(drill 0.2032)
		(layers "F.Cu" "B.Cu")
		(net "GND")
	)
	(via
		(at 214.615014 -250.866656)
		(size 0.4572)
		(drill 0.2032)
		(layers "F.Cu" "B.Cu")
		(net "GND")
	)
	(via
		(at 111.13008 -123.148598)
		(size 0.508)
		(drill 0.254)
		(layers "F.Cu" "B.Cu")
		(net "GND")
	)
	(via
		(at 63.942214 -277.216616)
		(size 0.4572)
		(drill 0.2032)
		(layers "F.Cu" "B.Cu")
		(net "GND")
	)
	(via
		(at 340.541356 -400.224244)
		(size 0.4572)
		(drill 0.254)
		(layers "F.Cu" "B.Cu")
		(net "GND")
	)
	(via
		(at 429.764952 -323.429376)
		(size 0.4572)
		(drill 0.2032)
		(layers "F.Cu" "B.Cu")
		(net "GND")
	)
	(via
		(at 464.764882 -261.066788)
		(size 0.4572)
		(drill 0.2032)
		(layers "F.Cu" "B.Cu")
		(net "GND")
	)
	(via
		(at 434.589682 -202.416664)
		(size 0.4572)
		(drill 0.2032)
		(layers "F.Cu" "B.Cu")
		(net "GND")
	)
	(via
		(at 430.489614 -309.51678)
		(size 0.4572)
		(drill 0.2032)
		(layers "F.Cu" "B.Cu")
		(net "GND")
	)
	(via
		(at 337.581748 -42.811446)
		(size 0.4572)
		(drill 0.2032)
		(layers "F.Cu" "B.Cu")
		(net "GND")
	)
	(via
		(at 308.10454 -403.249892)
		(size 0.4572)
		(drill 0.254)
		(layers "F.Cu" "B.Cu")
		(net "GND")
	)
	(via
		(at 339.374734 -223.575626)
		(size 0.4572)
		(drill 0.2032)
		(layers "F.Cu" "B.Cu")
		(net "GND")
	)
	(via
		(at 431.247296 -10.153396)
		(size 0.508)
		(drill 0.254)
		(layers "F.Cu" "B.Cu")
		(net "GND")
	)
	(via
		(at 197.637146 -242.3668)
		(size 0.4572)
		(drill 0.2032)
		(layers "F.Cu" "B.Cu")
		(net "GND")
	)
	(via
		(at 31.876746 -236.416596)
		(size 0.4572)
		(drill 0.2032)
		(layers "F.Cu" "B.Cu")
		(net "GND")
	)
	(via
		(at 457.943966 -97.864422)
		(size 0.508)
		(drill 0.254)
		(layers "F.Cu" "B.Cu")
		(net "GND")
	)
	(via
		(at 355.96576 -329.119738)
		(size 0.508)
		(drill 0.254)
		(layers "F.Cu" "B.Cu")
		(net "GND")
	)
	(via
		(at 188.15304 -359.19791)
		(size 0.508)
		(drill 0.254)
		(layers "F.Cu" "B.Cu")
		(net "GND")
	)
	(via
		(at 54.333648 -146.96567)
		(size 0.49022)
		(drill 0.254)
		(layers "F.Cu" "B.Cu")
		(net "GND")
	)
	(via
		(at 358.96042 -416.824668)
		(size 0.508)
		(drill 0.254)
		(layers "F.Cu" "B.Cu")
		(net "GND")
	)
	(via
		(at 13.345414 -211.766658)
		(size 0.4572)
		(drill 0.2032)
		(layers "F.Cu" "B.Cu")
		(net "GND")
	)
	(via
		(at 401.349972 -431.29962)
		(size 0.4572)
		(drill 0.2032)
		(layers "F.Cu" "B.Cu")
		(net "GND")
	)
	(via
		(at 91.434666 -220.319854)
		(size 0.4572)
		(drill 0.2032)
		(layers "F.Cu" "B.Cu")
		(net "GND")
	)
	(via
		(at 123.64339 -333.356458)
		(size 0.49022)
		(drill 0.254)
		(layers "F.Cu" "B.Cu")
		(net "GND")
	)
	(via
		(at 131.015994 -272.639282)
		(size 0.4572)
		(drill 0.2032)
		(layers "F.Cu" "B.Cu")
		(net "GND")
	)
	(via
		(at 85.177376 -278.711406)
		(size 0.4572)
		(drill 0.2032)
		(layers "F.Cu" "B.Cu")
		(net "GND")
	)
	(via
		(at 60.551822 -151.59228)
		(size 0.508)
		(drill 0.254)
		(layers "F.Cu" "B.Cu")
		(net "GND")
	)
	(via
		(at 59.842146 -265.316716)
		(size 0.4572)
		(drill 0.2032)
		(layers "F.Cu" "B.Cu")
		(net "GND")
	)
	(via
		(at 425.156884 -360.148378)
		(size 0.49022)
		(drill 0.254)
		(layers "F.Cu" "B.Cu")
		(net "GND")
	)
	(via
		(at 250.490228 -91.709748)
		(size 0.508)
		(drill 0.254)
		(layers "F.Cu" "B.Cu")
		(net "GND")
	)
	(via
		(at 449.677282 -288.266632)
		(size 0.4572)
		(drill 0.2032)
		(layers "F.Cu" "B.Cu")
		(net "GND")
	)
	(via
		(at 337.381088 -407.00452)
		(size 0.4064)
		(drill 0.2032)
		(layers "F.Cu" "B.Cu")
		(net "GND")
	)
	(via
		(at 369.23218 -70.65518)
		(size 0.508)
		(drill 0.254)
		(layers "F.Cu" "B.Cu")
		(net "GND")
	)
	(via
		(at 311.255156 -409.396184)
		(size 0.4572)
		(drill 0.254)
		(layers "F.Cu" "B.Cu")
		(net "GND")
	)
	(via
		(at 66.152014 -277.216616)
		(size 0.4572)
		(drill 0.2032)
		(layers "F.Cu" "B.Cu")
		(net "GND")
	)
	(via
		(at 345.593416 -273.453098)
		(size 0.4572)
		(drill 0.2032)
		(layers "F.Cu" "B.Cu")
		(net "GND")
	)
	(via
		(at 51.064414 -239.81664)
		(size 0.4572)
		(drill 0.2032)
		(layers "F.Cu" "B.Cu")
		(net "GND")
	)
	(via
		(at 447.467482 -222.816674)
		(size 0.4572)
		(drill 0.2032)
		(layers "F.Cu" "B.Cu")
		(net "GND")
	)
	(via
		(at 58.844942 -19.770344)
		(size 0.508)
		(drill 0.254)
		(layers "F.Cu" "B.Cu")
		(net "GND")
	)
	(via
		(at 299.004482 -286.56661)
		(size 0.4572)
		(drill 0.2032)
		(layers "F.Cu" "B.Cu")
		(net "GND")
	)
	(via
		(at 202.971146 -268.71676)
		(size 0.4572)
		(drill 0.2032)
		(layers "F.Cu" "B.Cu")
		(net "GND")
	)
	(via
		(at 432.379882 -312.91657)
		(size 0.4572)
		(drill 0.2032)
		(layers "F.Cu" "B.Cu")
		(net "GND")
	)
	(via
		(at 36.15309 -18.502376)
		(size 0.508)
		(drill 0.254)
		(layers "F.Cu" "B.Cu")
		(net "GND")
	)
	(via
		(at 395.093444 -6.586474)
		(size 0.508)
		(drill 0.254)
		(layers "F.Cu" "B.Cu")
		(net "GND")
	)
	(via
		(at 342.19388 -247.992138)
		(size 0.4572)
		(drill 0.2032)
		(layers "F.Cu" "B.Cu")
		(net "GND")
	)
	(via
		(at 300.238414 -231.316784)
		(size 0.4572)
		(drill 0.2032)
		(layers "F.Cu" "B.Cu")
		(net "GND")
	)
	(via
		(at 268.829282 -230.466646)
		(size 0.4572)
		(drill 0.2032)
		(layers "F.Cu" "B.Cu")
		(net "GND")
	)
	(via
		(at 169.755566 -104.575356)
		(size 0.4572)
		(drill 0.254)
		(layers "F.Cu" "B.Cu")
		(net "GND")
	)
	(via
		(at 382.245616 -284.847538)
		(size 0.4572)
		(drill 0.2032)
		(layers "F.Cu" "B.Cu")
		(net "GND")
	)
	(via
		(at 285.150814 -290.816792)
		(size 0.4572)
		(drill 0.2032)
		(layers "F.Cu" "B.Cu")
		(net "GND")
	)
	(via
		(at 37.210746 -238.966756)
		(size 0.4572)
		(drill 0.2032)
		(layers "F.Cu" "B.Cu")
		(net "GND")
	)
	(via
		(at 123.020582 -403.249892)
		(size 0.4572)
		(drill 0.254)
		(layers "F.Cu" "B.Cu")
		(net "GND")
	)
	(via
		(at 164.018214 -278.916638)
		(size 0.4572)
		(drill 0.2032)
		(layers "F.Cu" "B.Cu")
		(net "GND")
	)
	(via
		(at 331.067918 -40.931846)
		(size 0.4572)
		(drill 0.2032)
		(layers "F.Cu" "B.Cu")
		(net "GND")
	)
	(via
		(at 171.809918 -216.866724)
		(size 0.4572)
		(drill 0.2032)
		(layers "F.Cu" "B.Cu")
		(net "GND")
	)
	(via
		(at 46.964346 -195.616576)
		(size 0.4572)
		(drill 0.2032)
		(layers "F.Cu" "B.Cu")
		(net "GND")
	)
	(via
		(at 403.349968 -437.49976)
		(size 0.4572)
		(drill 0.2032)
		(layers "F.Cu" "B.Cu")
		(net "GND")
	)
	(via
		(at 125.737366 -243.922804)
		(size 0.4572)
		(drill 0.2032)
		(layers "F.Cu" "B.Cu")
		(net "GND")
	)
	(via
		(at 445.577214 -221.96679)
		(size 0.4572)
		(drill 0.2032)
		(layers "F.Cu" "B.Cu")
		(net "GND")
	)
	(via
		(at 417.292282 -262.76681)
		(size 0.4572)
		(drill 0.2032)
		(layers "F.Cu" "B.Cu")
		(net "GND")
	)
	(via
		(at 137.878566 -410.664152)
		(size 0.4572)
		(drill 0.254)
		(layers "F.Cu" "B.Cu")
		(net "GND")
	)
	(via
		(at 167.461946 -244.916706)
		(size 0.4572)
		(drill 0.2032)
		(layers "F.Cu" "B.Cu")
		(net "GND")
	)
	(via
		(at 134.195566 -247.178322)
		(size 0.4572)
		(drill 0.2032)
		(layers "F.Cu" "B.Cu")
		(net "GND")
	)
	(via
		(at 31.876746 -272.116804)
		(size 0.4572)
		(drill 0.2032)
		(layers "F.Cu" "B.Cu")
		(net "GND")
	)
	(via
		(at 302.448214 -267.016738)
		(size 0.4572)
		(drill 0.2032)
		(layers "F.Cu" "B.Cu")
		(net "GND")
	)
	(via
		(at 169.352214 -289.966654)
		(size 0.4572)
		(drill 0.2032)
		(layers "F.Cu" "B.Cu")
		(net "GND")
	)
	(via
		(at 79.023718 -336.08645)
		(size 0.6604)
		(drill 0.3302)
		(layers "F.Cu" "B.Cu")
		(net "GND")
	)
	(via
		(at 28.433014 -250.866656)
		(size 0.4572)
		(drill 0.2032)
		(layers "F.Cu" "B.Cu")
		(net "GND")
	)
	(via
		(at 182.549546 -240.666778)
		(size 0.4572)
		(drill 0.2032)
		(layers "F.Cu" "B.Cu")
		(net "GND")
	)
	(via
		(at 309.992014 -265.316716)
		(size 0.4572)
		(drill 0.2032)
		(layers "F.Cu" "B.Cu")
		(net "GND")
	)
	(via
		(at 208.054956 -29.266642)
		(size 0.508)
		(drill 0.254)
		(layers "F.Cu" "B.Cu")
		(net "GND")
	)
	(via
		(at 378.956062 -264.50036)
		(size 0.4572)
		(drill 0.2032)
		(layers "F.Cu" "B.Cu")
		(net "GND")
	)
	(via
		(at 384.350006 -437.34736)
		(size 0.4572)
		(drill 0.2032)
		(layers "F.Cu" "B.Cu")
		(net "GND")
	)
	(via
		(at 63.942214 -297.616626)
		(size 0.4572)
		(drill 0.2032)
		(layers "F.Cu" "B.Cu")
		(net "GND")
	)
	(via
		(at 387.45668 -241.203226)
		(size 0.4572)
		(drill 0.2032)
		(layers "F.Cu" "B.Cu")
		(net "GND")
	)
	(via
		(at 424.836082 -207.51673)
		(size 0.4572)
		(drill 0.2032)
		(layers "F.Cu" "B.Cu")
		(net "GND")
	)
	(via
		(at 122.978926 -123.112784)
		(size 0.508)
		(drill 0.254)
		(layers "F.Cu" "B.Cu")
		(net "GND")
	)
	(via
		(at 254.975614 -285.716726)
		(size 0.4572)
		(drill 0.2032)
		(layers "F.Cu" "B.Cu")
		(net "GND")
	)
	(via
		(at 96.966278 -332.56601)
		(size 0.49022)
		(drill 0.254)
		(layers "F.Cu" "B.Cu")
		(net "GND")
	)
	(via
		(at 155.14828 -120.106948)
		(size 0.508)
		(drill 0.254)
		(layers "F.Cu" "B.Cu")
		(net "GND")
	)
	(via
		(at 54.508146 -203.266802)
		(size 0.4572)
		(drill 0.2032)
		(layers "F.Cu" "B.Cu")
		(net "GND")
	)
	(via
		(at 96.751394 -335.704434)
		(size 0.49022)
		(drill 0.254)
		(layers "F.Cu" "B.Cu")
		(net "GND")
	)
	(via
		(at 29.666946 -295.06672)
		(size 0.4572)
		(drill 0.2032)
		(layers "F.Cu" "B.Cu")
		(net "GND")
	)
	(via
		(at 365.044228 -331.924914)
		(size 0.508)
		(drill 0.254)
		(layers "F.Cu" "B.Cu")
		(net "GND")
	)
	(via
		(at 178.289204 -52.799996)
		(size 0.508)
		(drill 0.254)
		(layers "F.Cu" "B.Cu")
		(net "GND")
	)
	(via
		(at 434.589682 -249.166634)
		(size 0.4572)
		(drill 0.2032)
		(layers "F.Cu" "B.Cu")
		(net "GND")
	)
	(via
		(at 39.420546 -268.71676)
		(size 0.4572)
		(drill 0.2032)
		(layers "F.Cu" "B.Cu")
		(net "GND")
	)
	(via
		(at 435.823614 -210.916774)
		(size 0.4572)
		(drill 0.2032)
		(layers "F.Cu" "B.Cu")
		(net "GND")
	)
	(via
		(at 164.018214 -301.01667)
		(size 0.4572)
		(drill 0.2032)
		(layers "F.Cu" "B.Cu")
		(net "GND")
	)
	(via
		(at 464.764882 -204.116686)
		(size 0.4572)
		(drill 0.2032)
		(layers "F.Cu" "B.Cu")
		(net "GND")
	)
	(via
		(at 430.044098 -180.86197)
		(size 0.6604)
		(drill 0.3302)
		(layers "F.Cu" "B.Cu")
		(net "GND")
	)
	(via
		(at 306.548282 -280.61666)
		(size 0.4572)
		(drill 0.2032)
		(layers "F.Cu" "B.Cu")
		(net "GND")
	)
	(via
		(at 306.548282 -213.46668)
		(size 0.4572)
		(drill 0.2032)
		(layers "F.Cu" "B.Cu")
		(net "GND")
	)
	(via
		(at 56.834786 -167.30345)
		(size 0.49022)
		(drill 0.254)
		(layers "F.Cu" "B.Cu")
		(net "GND")
	)
	(via
		(at 26.223214 -266.1666)
		(size 0.4572)
		(drill 0.2032)
		(layers "F.Cu" "B.Cu")
		(net "GND")
	)
	(via
		(at 420.736014 -201.56678)
		(size 0.4572)
		(drill 0.2032)
		(layers "F.Cu" "B.Cu")
		(net "GND")
	)
	(via
		(at 207.071214 -316.316614)
		(size 0.4572)
		(drill 0.2032)
		(layers "F.Cu" "B.Cu")
		(net "GND")
	)
	(via
		(at 340.784434 -229.272846)
		(size 0.4572)
		(drill 0.2032)
		(layers "F.Cu" "B.Cu")
		(net "GND")
	)
	(via
		(at 314.092082 -213.46668)
		(size 0.4572)
		(drill 0.2032)
		(layers "F.Cu" "B.Cu")
		(net "GND")
	)
	(via
		(at 256.949194 -109.229652)
		(size 0.508)
		(drill 0.254)
		(layers "F.Cu" "B.Cu")
		(net "GND")
	)
	(via
		(at 117.075458 -329.89012)
		(size 0.508)
		(drill 0.254)
		(layers "F.Cu" "B.Cu")
		(net "GND")
	)
	(via
		(at 204.49413 -12.544552)
		(size 0.508)
		(drill 0.254)
		(layers "F.Cu" "B.Cu")
		(net "GND")
	)
	(via
		(at 89.664794 -274.266914)
		(size 0.4572)
		(drill 0.2032)
		(layers "F.Cu" "B.Cu")
		(net "GND")
	)
	(via
		(at 137.733024 -347.96349)
		(size 0.508)
		(drill 0.254)
		(layers "F.Cu" "B.Cu")
		(net "GND")
	)
	(via
		(at 374.147334 -233.34218)
		(size 0.4572)
		(drill 0.2032)
		(layers "F.Cu" "B.Cu")
		(net "GND")
	)
	(via
		(at 326.64527 -341.85225)
		(size 0.49022)
		(drill 0.254)
		(layers "F.Cu" "B.Cu")
		(net "GND")
	)
	(via
		(at 460.0575 -387.30682)
		(size 0.508)
		(drill 0.254)
		(layers "F.Cu" "B.Cu")
		(net "GND")
	)
	(via
		(at 212.000084 -323.434456)
		(size 0.4572)
		(drill 0.2032)
		(layers "F.Cu" "B.Cu")
		(net "GND")
	)
	(via
		(at 56.049672 -146.489674)
		(size 0.49022)
		(drill 0.254)
		(layers "F.Cu" "B.Cu")
		(net "GND")
	)
	(via
		(at 58.180732 -0.76454)
		(size 0.508)
		(drill 0.254)
		(layers "F.Cu" "B.Cu")
		(net "GND")
	)
	(via
		(at 361.460034 -229.272846)
		(size 0.4572)
		(drill 0.2032)
		(layers "F.Cu" "B.Cu")
		(net "GND")
	)
	(via
		(at 128.998726 -336.765392)
		(size 0.49022)
		(drill 0.254)
		(layers "F.Cu" "B.Cu")
		(net "GND")
	)
	(via
		(at 291.460682 -200.716642)
		(size 0.4572)
		(drill 0.2032)
		(layers "F.Cu" "B.Cu")
		(net "GND")
	)
	(via
		(at 43.549824 -399.405856)
		(size 0.508)
		(drill 0.254)
		(layers "F.Cu" "B.Cu")
		(net "GND")
	)
	(via
		(at 411.958282 -264.466578)
		(size 0.4572)
		(drill 0.2032)
		(layers "F.Cu" "B.Cu")
		(net "GND")
	)
	(via
		(at 120.60301 -335.704434)
		(size 0.49022)
		(drill 0.254)
		(layers "F.Cu" "B.Cu")
		(net "GND")
	)
	(via
		(at 294.904414 -313.766708)
		(size 0.4572)
		(drill 0.2032)
		(layers "F.Cu" "B.Cu")
		(net "GND")
	)
	(via
		(at 39.420546 -216.016586)
		(size 0.4572)
		(drill 0.2032)
		(layers "F.Cu" "B.Cu")
		(net "GND")
	)
	(via
		(at 144.77111 -40.952928)
		(size 0.508)
		(drill 0.254)
		(layers "F.Cu" "B.Cu")
		(net "GND")
	)
	(via
		(at 353.119436 -239.292638)
		(size 0.4572)
		(drill 0.2032)
		(layers "F.Cu" "B.Cu")
		(net "GND")
	)
	(via
		(at 127.616966 -240.667286)
		(size 0.4572)
		(drill 0.2032)
		(layers "F.Cu" "B.Cu")
		(net "GND")
	)
	(via
		(at 43.520614 -288.266632)
		(size 0.4572)
		(drill 0.2032)
		(layers "F.Cu" "B.Cu")
		(net "GND")
	)
	(via
		(at 92.954348 -260.430772)
		(size 0.4572)
		(drill 0.2032)
		(layers "F.Cu" "B.Cu")
		(net "GND")
	)
	(via
		(at 70.209918 -407.00452)
		(size 0.4064)
		(drill 0.2032)
		(layers "F.Cu" "B.Cu")
		(net "GND")
	)
	(via
		(at 56.049672 -155.786074)
		(size 0.49022)
		(drill 0.254)
		(layers "F.Cu" "B.Cu")
		(net "GND")
	)
	(via
		(at 67.507866 -409.396184)
		(size 0.4572)
		(drill 0.254)
		(layers "F.Cu" "B.Cu")
		(net "GND")
	)
	(via
		(at 288.144966 -362.414566)
		(size 0.49022)
		(drill 0.254)
		(layers "F.Cu" "B.Cu")
		(net "GND")
	)
	(via
		(at 136.448038 -340.977728)
		(size 0.49022)
		(drill 0.254)
		(layers "F.Cu" "B.Cu")
		(net "GND")
	)
	(via
		(at 167.461946 -261.916672)
		(size 0.4572)
		(drill 0.2032)
		(layers "F.Cu" "B.Cu")
		(net "GND")
	)
	(via
		(at 134.349998 -425.547282)
		(size 0.4572)
		(drill 0.2032)
		(layers "F.Cu" "B.Cu")
		(net "GND")
	)
	(via
		(at 422.945814 -307.816758)
		(size 0.4572)
		(drill 0.2032)
		(layers "F.Cu" "B.Cu")
		(net "GND")
	)
	(via
		(at 420.736014 -236.416596)
		(size 0.4572)
		(drill 0.2032)
		(layers "F.Cu" "B.Cu")
		(net "GND")
	)
	(via
		(at 37.210746 -315.46673)
		(size 0.4572)
		(drill 0.2032)
		(layers "F.Cu" "B.Cu")
		(net "GND")
	)
	(via
		(at 175.005746 -306.116736)
		(size 0.4572)
		(drill 0.2032)
		(layers "F.Cu" "B.Cu")
		(net "GND")
	)
	(via
		(at 353.587304 -339.257132)
		(size 0.508)
		(drill 0.254)
		(layers "F.Cu" "B.Cu")
		(net "GND")
	)
	(via
		(at 417.289742 -151.131524)
		(size 0.508)
		(drill 0.254)
		(layers "F.Cu" "B.Cu")
		(net "GND")
	)
	(via
		(at 418.15893 -407.00452)
		(size 0.4064)
		(drill 0.2032)
		(layers "F.Cu" "B.Cu")
		(net "GND")
	)
	(via
		(at 176.155604 -111.775494)
		(size 0.4572)
		(drill 0.254)
		(layers "F.Cu" "B.Cu")
		(net "GND")
	)
	(via
		(at 333.845662 -269.38351)
		(size 0.4318)
		(drill 0.2032)
		(layers "F.Cu" "B.Cu")
		(net "GND")
	)
	(via
		(at 266.619482 -305.266598)
		(size 0.4572)
		(drill 0.2032)
		(layers "F.Cu" "B.Cu")
		(net "GND")
	)
	(via
		(at 178.55565 -105.375456)
		(size 0.4572)
		(drill 0.254)
		(layers "F.Cu" "B.Cu")
		(net "GND")
	)
	(via
		(at 337.49488 -226.831144)
		(size 0.4572)
		(drill 0.2032)
		(layers "F.Cu" "B.Cu")
		(net "GND")
	)
	(via
		(at 361.569762 -288.103056)
		(size 0.4572)
		(drill 0.2032)
		(layers "F.Cu" "B.Cu")
		(net "GND")
	)
	(via
		(at 222.535496 -21.862288)
		(size 0.508)
		(drill 0.254)
		(layers "F.Cu" "B.Cu")
		(net "GND")
	)
	(via
		(at 431.662078 -367.74247)
		(size 0.49022)
		(drill 0.254)
		(layers "F.Cu" "B.Cu")
		(net "GND")
	)
	(via
		(at 52.298346 -272.116804)
		(size 0.4572)
		(drill 0.2032)
		(layers "F.Cu" "B.Cu")
		(net "GND")
	)
	(via
		(at 130.414776 -120.213374)
		(size 0.508)
		(drill 0.254)
		(layers "F.Cu" "B.Cu")
		(net "GND")
	)
	(via
		(at 136.924034 -344.90533)
		(size 0.49022)
		(drill 0.254)
		(layers "F.Cu" "B.Cu")
		(net "GND")
	)
	(via
		(at 58.23077 -404.51786)
		(size 0.4572)
		(drill 0.254)
		(layers "F.Cu" "B.Cu")
		(net "GND")
	)
	(via
		(at 413.652462 -406.370536)
		(size 0.4572)
		(drill 0.254)
		(layers "F.Cu" "B.Cu")
		(net "GND")
	)
	(via
		(at 171.562014 -284.866588)
		(size 0.4572)
		(drill 0.2032)
		(layers "F.Cu" "B.Cu")
		(net "GND")
	)
	(via
		(at 351.745804 -331.776832)
		(size 0.49022)
		(drill 0.254)
		(layers "F.Cu" "B.Cu")
		(net "GND")
	)
	(via
		(at 184.439814 -267.866622)
		(size 0.4572)
		(drill 0.2032)
		(layers "F.Cu" "B.Cu")
		(net "GND")
	)
	(via
		(at 415.402014 -223.666558)
		(size 0.4572)
		(drill 0.2032)
		(layers "F.Cu" "B.Cu")
		(net "GND")
	)
	(via
		(at 35.976814 -228.766624)
		(size 0.4572)
		(drill 0.2032)
		(layers "F.Cu" "B.Cu")
		(net "GND")
	)
	(via
		(at 29.666946 -220.266768)
		(size 0.4572)
		(drill 0.2032)
		(layers "F.Cu" "B.Cu")
		(net "GND")
	)
	(via
		(at 14.426946 -392.199876)
		(size 0.508)
		(drill 0.254)
		(layers "F.Cu" "B.Cu")
		(net "GND")
	)
	(via
		(at 403.846792 -10.16508)
		(size 0.508)
		(drill 0.254)
		(layers "F.Cu" "B.Cu")
		(net "GND")
	)
	(via
		(at 343.604596 -404.51786)
		(size 0.4572)
		(drill 0.254)
		(layers "F.Cu" "B.Cu")
		(net "GND")
	)
	(via
		(at 56.744362 -159.56788)
		(size 0.508)
		(drill 0.254)
		(layers "F.Cu" "B.Cu")
		(net "GND")
	)
	(via
		(at 210.514946 -304.416714)
		(size 0.4572)
		(drill 0.2032)
		(layers "F.Cu" "B.Cu")
		(net "GND")
	)
	(via
		(at 197.637146 -281.466798)
		(size 0.4572)
		(drill 0.2032)
		(layers "F.Cu" "B.Cu")
		(net "GND")
	)
	(via
		(at 68.672456 -30.07741)
		(size 0.508)
		(drill 0.254)
		(layers "F.Cu" "B.Cu")
		(net "GND")
	)
	(via
		(at 432.379882 -235.566712)
		(size 0.4572)
		(drill 0.2032)
		(layers "F.Cu" "B.Cu")
		(net "GND")
	)
	(via
		(at 100.002594 -284.033722)
		(size 0.4572)
		(drill 0.2032)
		(layers "F.Cu" "B.Cu")
		(net "GND")
	)
	(via
		(at 351.701862 -287.28924)
		(size 0.4572)
		(drill 0.2032)
		(layers "F.Cu" "B.Cu")
		(net "GND")
	)
	(via
		(at 445.577214 -212.616796)
		(size 0.4572)
		(drill 0.2032)
		(layers "F.Cu" "B.Cu")
		(net "GND")
	)
	(via
		(at 119.268494 -283.219906)
		(size 0.4572)
		(drill 0.2032)
		(layers "F.Cu" "B.Cu")
		(net "GND")
	)
	(via
		(at 108.43387 -258.994402)
		(size 0.4572)
		(drill 0.2032)
		(layers "F.Cu" "B.Cu")
		(net "GND")
	)
	(via
		(at 37.210746 -214.316564)
		(size 0.4572)
		(drill 0.2032)
		(layers "F.Cu" "B.Cu")
		(net "GND")
	)
	(via
		(at 175.005746 -240.666778)
		(size 0.4572)
		(drill 0.2032)
		(layers "F.Cu" "B.Cu")
		(net "GND")
	)
	(via
		(at 428.279814 -301.866808)
		(size 0.4572)
		(drill 0.2032)
		(layers "F.Cu" "B.Cu")
		(net "GND")
	)
	(via
		(at 332.250034 -433.899564)
		(size 0.4572)
		(drill 0.2032)
		(layers "F.Cu" "B.Cu")
		(net "GND")
	)
	(via
		(at 192.685924 -6.044438)
		(size 0.508)
		(drill 0.254)
		(layers "F.Cu" "B.Cu")
		(net "GND")
	)
	(via
		(at 48.662082 -17.61236)
		(size 0.508)
		(drill 0.254)
		(layers "F.Cu" "B.Cu")
		(net "GND")
	)
	(via
		(at 411.958282 -286.56661)
		(size 0.4572)
		(drill 0.2032)
		(layers "F.Cu" "B.Cu")
		(net "GND")
	)
	(via
		(at 20.889214 -235.566712)
		(size 0.4572)
		(drill 0.2032)
		(layers "F.Cu" "B.Cu")
		(net "GND")
	)
	(via
		(at 209.281014 -232.166668)
		(size 0.4572)
		(drill 0.2032)
		(layers "F.Cu" "B.Cu")
		(net "GND")
	)
	(via
		(at 266.619482 -288.266632)
		(size 0.4572)
		(drill 0.2032)
		(layers "F.Cu" "B.Cu")
		(net "GND")
	)
	(via
		(at 164.018214 -277.216616)
		(size 0.4572)
		(drill 0.2032)
		(layers "F.Cu" "B.Cu")
		(net "GND")
	)
	(via
		(at 11.135614 -205.816708)
		(size 0.4572)
		(drill 0.2032)
		(layers "F.Cu" "B.Cu")
		(net "GND")
	)
	(via
		(at 62.051946 -317.166752)
		(size 0.4572)
		(drill 0.2032)
		(layers "F.Cu" "B.Cu")
		(net "GND")
	)
	(via
		(at 274.163282 -194.766692)
		(size 0.4572)
		(drill 0.2032)
		(layers "F.Cu" "B.Cu")
		(net "GND")
	)
	(via
		(at 349.556832 -330.382626)
		(size 0.508)
		(drill 0.254)
		(layers "F.Cu" "B.Cu")
		(net "GND")
	)
	(via
		(at 354.881434 -226.017328)
		(size 0.4572)
		(drill 0.2032)
		(layers "F.Cu" "B.Cu")
		(net "GND")
	)
	(via
		(at 418.832538 -375.08053)
		(size 0.508)
		(drill 0.254)
		(layers "F.Cu" "B.Cu")
		(net "GND")
	)
	(via
		(at 458.455014 -234.716574)
		(size 0.4572)
		(drill 0.2032)
		(layers "F.Cu" "B.Cu")
		(net "GND")
	)
	(via
		(at 120.98909 -249.107198)
		(size 0.4572)
		(drill 0.2032)
		(layers "F.Cu" "B.Cu")
		(net "GND")
	)
	(via
		(at 411.047438 -401.492212)
		(size 0.4572)
		(drill 0.254)
		(layers "F.Cu" "B.Cu")
		(net "GND")
	)
	(via
		(at 419.778942 -409.396184)
		(size 0.4572)
		(drill 0.254)
		(layers "F.Cu" "B.Cu")
		(net "GND")
	)
	(via
		(at 415.402014 -281.466798)
		(size 0.4572)
		(drill 0.2032)
		(layers "F.Cu" "B.Cu")
		(net "GND")
	)
	(via
		(at 39.420546 -217.716608)
		(size 0.4572)
		(drill 0.2032)
		(layers "F.Cu" "B.Cu")
		(net "GND")
	)
	(via
		(at 304.338482 -239.81664)
		(size 0.4572)
		(drill 0.2032)
		(layers "F.Cu" "B.Cu")
		(net "GND")
	)
	(via
		(at 132.350002 -431.29962)
		(size 0.4572)
		(drill 0.2032)
		(layers "F.Cu" "B.Cu")
		(net "GND")
	)
	(via
		(at 311.666382 -310.366664)
		(size 0.4572)
		(drill 0.2032)
		(layers "F.Cu" "B.Cu")
		(net "GND")
	)
	(via
		(at 370.86413 -403.883876)
		(size 0.4064)
		(drill 0.2032)
		(layers "F.Cu" "B.Cu")
		(net "GND")
	)
	(via
		(at 428.279814 -203.266802)
		(size 0.4572)
		(drill 0.2032)
		(layers "F.Cu" "B.Cu")
		(net "GND")
	)
	(via
		(at 445.577214 -227.066602)
		(size 0.4572)
		(drill 0.2032)
		(layers "F.Cu" "B.Cu")
		(net "GND")
	)
	(via
		(at 239.478058 -109.138466)
		(size 0.508)
		(drill 0.254)
		(layers "F.Cu" "B.Cu")
		(net "GND")
	)
	(via
		(at 254.975614 -250.016772)
		(size 0.4572)
		(drill 0.2032)
		(layers "F.Cu" "B.Cu")
		(net "GND")
	)
	(via
		(at 415.402014 -225.36658)
		(size 0.4572)
		(drill 0.2032)
		(layers "F.Cu" "B.Cu")
		(net "GND")
	)
	(via
		(at 445.577214 -287.416748)
		(size 0.4572)
		(drill 0.2032)
		(layers "F.Cu" "B.Cu")
		(net "GND")
	)
	(via
		(at 304.338482 -213.46668)
		(size 0.4572)
		(drill 0.2032)
		(layers "F.Cu" "B.Cu")
		(net "GND")
	)
	(via
		(at 337.49488 -239.853216)
		(size 0.4572)
		(drill 0.2032)
		(layers "F.Cu" "B.Cu")
		(net "GND")
	)
	(via
		(at 26.223214 -278.916638)
		(size 0.4572)
		(drill 0.2032)
		(layers "F.Cu" "B.Cu")
		(net "GND")
	)
	(via
		(at 169.352214 -213.46668)
		(size 0.4572)
		(drill 0.2032)
		(layers "F.Cu" "B.Cu")
		(net "GND")
	)
	(via
		(at 72.87768 -63.157608)
		(size 0.508)
		(drill 0.254)
		(layers "F.Cu" "B.Cu")
		(net "GND")
	)
	(via
		(at 306.615592 -207.658716)
		(size 0.4572)
		(drill 0.2032)
		(layers "F.Cu" "B.Cu")
		(net "GND")
	)
	(via
		(at 2.764536 -203.630022)
		(size 0.508)
		(drill 0.254)
		(layers "F.Cu" "B.Cu")
		(net "GND")
	)
	(via
		(at 87.604346 -404.51786)
		(size 0.4572)
		(drill 0.254)
		(layers "F.Cu" "B.Cu")
		(net "GND")
	)
	(via
		(at 300.238414 -287.416748)
		(size 0.4572)
		(drill 0.2032)
		(layers "F.Cu" "B.Cu")
		(net "GND")
	)
	(via
		(at 328.397616 -198.640192)
		(size 0.508)
		(drill 0.254)
		(layers "F.Cu" "B.Cu")
		(net "GND")
	)
	(via
		(at 377.546616 -273.453098)
		(size 0.4572)
		(drill 0.2032)
		(layers "F.Cu" "B.Cu")
		(net "GND")
	)
	(via
		(at 48.854614 -291.666676)
		(size 0.4572)
		(drill 0.2032)
		(layers "F.Cu" "B.Cu")
		(net "GND")
	)
	(via
		(at 300.238414 -242.3668)
		(size 0.4572)
		(drill 0.2032)
		(layers "F.Cu" "B.Cu")
		(net "GND")
	)
	(via
		(at 372.21033 -410.030168)
		(size 0.4064)
		(drill 0.2032)
		(layers "F.Cu" "B.Cu")
		(net "GND")
	)
	(via
		(at 163.18992 -46.954948)
		(size 0.508)
		(drill 0.254)
		(layers "F.Cu" "B.Cu")
		(net "GND")
	)
	(via
		(at 41.310814 -233.86669)
		(size 0.4572)
		(drill 0.2032)
		(layers "F.Cu" "B.Cu")
		(net "GND")
	)
	(via
		(at 165.252146 -292.516814)
		(size 0.4572)
		(drill 0.2032)
		(layers "F.Cu" "B.Cu")
		(net "GND")
	)
	(via
		(at 291.460682 -291.666676)
		(size 0.4572)
		(drill 0.2032)
		(layers "F.Cu" "B.Cu")
		(net "GND")
	)
	(via
		(at 407.858214 -317.166752)
		(size 0.4572)
		(drill 0.2032)
		(layers "F.Cu" "B.Cu")
		(net "GND")
	)
	(via
		(at 39.420546 -278.066754)
		(size 0.4572)
		(drill 0.2032)
		(layers "F.Cu" "B.Cu")
		(net "GND")
	)
	(via
		(at 179.105814 -291.666676)
		(size 0.4572)
		(drill 0.2032)
		(layers "F.Cu" "B.Cu")
		(net "GND")
	)
	(via
		(at 339.209888 -40.931846)
		(size 0.4572)
		(drill 0.2032)
		(layers "F.Cu" "B.Cu")
		(net "GND")
	)
	(via
		(at 375.087134 -220.319854)
		(size 0.4572)
		(drill 0.2032)
		(layers "F.Cu" "B.Cu")
		(net "GND")
	)
	(via
		(at 435.823614 -301.866808)
		(size 0.4572)
		(drill 0.2032)
		(layers "F.Cu" "B.Cu")
		(net "GND")
	)
	(via
		(at 447.467482 -204.116686)
		(size 0.4572)
		(drill 0.2032)
		(layers "F.Cu" "B.Cu")
		(net "GND")
	)
	(via
		(at 323.250052 -426.69968)
		(size 0.4572)
		(drill 0.2032)
		(layers "F.Cu" "B.Cu")
		(net "GND")
	)
	(via
		(at 114.459766 -219.506038)
		(size 0.4572)
		(drill 0.2032)
		(layers "F.Cu" "B.Cu")
		(net "GND")
	)
	(via
		(at 363.919262 -279.150318)
		(size 0.4572)
		(drill 0.2032)
		(layers "F.Cu" "B.Cu")
		(net "GND")
	)
	(via
		(at 159.918146 -258.516628)
		(size 0.4572)
		(drill 0.2032)
		(layers "F.Cu" "B.Cu")
		(net "GND")
	)
	(via
		(at 422.945814 -206.666592)
		(size 0.4572)
		(drill 0.2032)
		(layers "F.Cu" "B.Cu")
		(net "GND")
	)
	(via
		(at 91.001342 -336.766662)
		(size 0.49022)
		(drill 0.254)
		(layers "F.Cu" "B.Cu")
		(net "GND")
	)
	(via
		(at 274.163282 -247.466612)
		(size 0.4572)
		(drill 0.2032)
		(layers "F.Cu" "B.Cu")
		(net "GND")
	)
	(via
		(at 26.223214 -216.866724)
		(size 0.4572)
		(drill 0.2032)
		(layers "F.Cu" "B.Cu")
		(net "GND")
	)
	(via
		(at 167.665146 -276.366732)
		(size 0.4572)
		(drill 0.2032)
		(layers "F.Cu" "B.Cu")
		(net "GND")
	)
	(via
		(at 13.345414 -233.86669)
		(size 0.4572)
		(drill 0.2032)
		(layers "F.Cu" "B.Cu")
		(net "GND")
	)
	(via
		(at 428.279814 -248.31675)
		(size 0.4572)
		(drill 0.2032)
		(layers "F.Cu" "B.Cu")
		(net "GND")
	)
	(via
		(at 363.693964 -441.225432)
		(size 0.508)
		(drill 0.254)
		(layers "F.Cu" "B.Cu")
		(net "GND")
	)
	(via
		(at 125.737366 -222.761556)
		(size 0.4572)
		(drill 0.2032)
		(layers "F.Cu" "B.Cu")
		(net "GND")
	)
	(via
		(at 100.472748 -260.430772)
		(size 0.4572)
		(drill 0.2032)
		(layers "F.Cu" "B.Cu")
		(net "GND")
	)
	(via
		(at 38.83533 -441.225432)
		(size 0.508)
		(drill 0.254)
		(layers "F.Cu" "B.Cu")
		(net "GND")
	)
	(via
		(at 123.387612 -239.853216)
		(size 0.4572)
		(drill 0.2032)
		(layers "F.Cu" "B.Cu")
		(net "GND")
	)
	(via
		(at 425.96689 -9.424924)
		(size 0.508)
		(drill 0.254)
		(layers "F.Cu" "B.Cu")
		(net "GND")
	)
	(via
		(at 405.648414 -240.666778)
		(size 0.4572)
		(drill 0.2032)
		(layers "F.Cu" "B.Cu")
		(net "GND")
	)
	(via
		(at 85.79993 -401.492212)
		(size 0.4572)
		(drill 0.254)
		(layers "F.Cu" "B.Cu")
		(net "GND")
	)
	(via
		(at 197.637146 -301.866808)
		(size 0.4572)
		(drill 0.2032)
		(layers "F.Cu" "B.Cu")
		(net "GND")
	)
	(via
		(at 285.413196 -360.714544)
		(size 0.508)
		(drill 0.254)
		(layers "F.Cu" "B.Cu")
		(net "GND")
	)
	(via
		(at 112.110266 -238.225838)
		(size 0.4572)
		(drill 0.2032)
		(layers "F.Cu" "B.Cu")
		(net "GND")
	)
	(via
		(at 418.133276 -4.95173)
		(size 0.508)
		(drill 0.254)
		(layers "F.Cu" "B.Cu")
		(net "GND")
	)
	(via
		(at 377.076462 -284.033722)
		(size 0.4572)
		(drill 0.2032)
		(layers "F.Cu" "B.Cu")
		(net "GND")
	)
	(via
		(at 45.392594 -4.328668)
		(size 0.508)
		(drill 0.254)
		(layers "F.Cu" "B.Cu")
		(net "GND")
	)
	(via
		(at 277.607014 -244.916706)
		(size 0.4572)
		(drill 0.2032)
		(layers "F.Cu" "B.Cu")
		(net "GND")
	)
	(via
		(at 176.955704 -121.375424)
		(size 0.4572)
		(drill 0.254)
		(layers "F.Cu" "B.Cu")
		(net "GND")
	)
	(via
		(at 56.867044 -12.37488)
		(size 0.508)
		(drill 0.254)
		(layers "F.Cu" "B.Cu")
		(net "GND")
	)
	(via
		(at 110.340648 -262.872728)
		(size 0.4572)
		(drill 0.2032)
		(layers "F.Cu" "B.Cu")
		(net "GND")
	)
	(via
		(at 127.83566 -35.684968)
		(size 0.508)
		(drill 0.254)
		(layers "F.Cu" "B.Cu")
		(net "GND")
	)
	(via
		(at 106.673396 -358.848406)
		(size 0.508)
		(drill 0.254)
		(layers "F.Cu" "B.Cu")
		(net "GND")
	)
	(via
		(at 132.895594 -256.361438)
		(size 0.4572)
		(drill 0.2032)
		(layers "F.Cu" "B.Cu")
		(net "GND")
	)
	(via
		(at 455.90714 -11.321542)
		(size 0.508)
		(drill 0.254)
		(layers "F.Cu" "B.Cu")
		(net "GND")
	)
	(via
		(at 417.292282 -224.516696)
		(size 0.4572)
		(drill 0.2032)
		(layers "F.Cu" "B.Cu")
		(net "GND")
	)
	(via
		(at 449.677282 -249.166634)
		(size 0.4572)
		(drill 0.2032)
		(layers "F.Cu" "B.Cu")
		(net "GND")
	)
	(via
		(at 399.349976 -435.0512)
		(size 0.4572)
		(drill 0.2032)
		(layers "F.Cu" "B.Cu")
		(net "GND")
	)
	(via
		(at 336.74558 -335.976214)
		(size 0.49022)
		(drill 0.254)
		(layers "F.Cu" "B.Cu")
		(net "GND")
	)
	(via
		(at 287.360614 -258.516628)
		(size 0.4572)
		(drill 0.2032)
		(layers "F.Cu" "B.Cu")
		(net "GND")
	)
	(via
		(at 191.983614 -277.216616)
		(size 0.4572)
		(drill 0.2032)
		(layers "F.Cu" "B.Cu")
		(net "GND")
	)
	(via
		(at 212.724746 -311.216802)
		(size 0.4572)
		(drill 0.2032)
		(layers "F.Cu" "B.Cu")
		(net "GND")
	)
	(via
		(at 371.662706 -181.226968)
		(size 0.508)
		(drill 0.254)
		(layers "F.Cu" "B.Cu")
		(net "GND")
	)
	(via
		(at 43.520614 -272.966688)
		(size 0.4572)
		(drill 0.2032)
		(layers "F.Cu" "B.Cu")
		(net "GND")
	)
	(via
		(at 335.615534 -231.714548)
		(size 0.4572)
		(drill 0.2032)
		(layers "F.Cu" "B.Cu")
		(net "GND")
	)
	(via
		(at 414.16478 -158.435548)
		(size 0.508)
		(drill 0.254)
		(layers "F.Cu" "B.Cu")
		(net "GND")
	)
	(via
		(at 123.497848 -279.150318)
		(size 0.4572)
		(drill 0.2032)
		(layers "F.Cu" "B.Cu")
		(net "GND")
	)
	(via
		(at 134.349998 -435.0512)
		(size 0.4572)
		(drill 0.2032)
		(layers "F.Cu" "B.Cu")
		(net "GND")
	)
	(via
		(at 363.449616 -271.825212)
		(size 0.4572)
		(drill 0.2032)
		(layers "F.Cu" "B.Cu")
		(net "GND")
	)
	(via
		(at 201.737214 -211.766658)
		(size 0.4572)
		(drill 0.2032)
		(layers "F.Cu" "B.Cu")
		(net "GND")
	)
	(via
		(at 384.350006 -428.851314)
		(size 0.4572)
		(drill 0.2032)
		(layers "F.Cu" "B.Cu")
		(net "GND")
	)
	(via
		(at 165.905942 -400.224244)
		(size 0.4572)
		(drill 0.254)
		(layers "F.Cu" "B.Cu")
		(net "GND")
	)
	(via
		(at 118.798848 -275.8948)
		(size 0.4572)
		(drill 0.2032)
		(layers "F.Cu" "B.Cu")
		(net "GND")
	)
	(via
		(at 25.999186 -126.332996)
		(size 0.508)
		(drill 0.254)
		(layers "F.Cu" "B.Cu")
		(net "GND")
	)
	(via
		(at 369.506754 -176.375568)
		(size 0.508)
		(drill 0.254)
		(layers "F.Cu" "B.Cu")
		(net "GND")
	)
	(via
		(at 159.918146 -276.366732)
		(size 0.4572)
		(drill 0.2032)
		(layers "F.Cu" "B.Cu")
		(net "GND")
	)
	(via
		(at 58.608214 -211.766658)
		(size 0.4572)
		(drill 0.2032)
		(layers "F.Cu" "B.Cu")
		(net "GND")
	)
	(via
		(at 95.303594 -277.522432)
		(size 0.4572)
		(drill 0.2032)
		(layers "F.Cu" "B.Cu")
		(net "GND")
	)
	(via
		(at 172.795946 -227.066602)
		(size 0.4572)
		(drill 0.2032)
		(layers "F.Cu" "B.Cu")
		(net "GND")
	)
	(via
		(at 332.733904 -269.94866)
		(size 0.4572)
		(drill 0.2032)
		(layers "F.Cu" "B.Cu")
		(net "GND")
	)
	(via
		(at 306.548282 -278.916638)
		(size 0.4572)
		(drill 0.2032)
		(layers "F.Cu" "B.Cu")
		(net "GND")
	)
	(via
		(at 434.589682 -297.616626)
		(size 0.4572)
		(drill 0.2032)
		(layers "F.Cu" "B.Cu")
		(net "GND")
	)
	(via
		(at 352.531934 -220.319854)
		(size 0.4572)
		(drill 0.2032)
		(layers "F.Cu" "B.Cu")
		(net "GND")
	)
	(via
		(at 340.424262 -284.033722)
		(size 0.4572)
		(drill 0.2032)
		(layers "F.Cu" "B.Cu")
		(net "GND")
	)
	(via
		(at 335.615534 -223.575626)
		(size 0.4572)
		(drill 0.2032)
		(layers "F.Cu" "B.Cu")
		(net "GND")
	)
	(via
		(at 413.192214 -292.516814)
		(size 0.4572)
		(drill 0.2032)
		(layers "F.Cu" "B.Cu")
		(net "GND")
	)
	(via
		(at 257.185414 -236.416596)
		(size 0.4572)
		(drill 0.2032)
		(layers "F.Cu" "B.Cu")
		(net "GND")
	)
	(via
		(at 347.847666 -52.929536)
		(size 0.49022)
		(drill 0.254)
		(layers "F.Cu" "B.Cu")
		(net "GND")
	)
	(via
		(at 211.2518 -151.628348)
		(size 0.508)
		(drill 0.254)
		(layers "F.Cu" "B.Cu")
		(net "GND")
	)
	(via
		(at 346.379292 -331.776832)
		(size 0.49022)
		(drill 0.254)
		(layers "F.Cu" "B.Cu")
		(net "GND")
	)
	(via
		(at 328.625708 -50.329846)
		(size 0.4572)
		(drill 0.2032)
		(layers "F.Cu" "B.Cu")
		(net "GND")
	)
	(via
		(at 421.502332 -161.835846)
		(size 0.508)
		(drill 0.254)
		(layers "F.Cu" "B.Cu")
		(net "GND")
	)
	(via
		(at 376.893582 -410.664152)
		(size 0.4572)
		(drill 0.254)
		(layers "F.Cu" "B.Cu")
		(net "GND")
	)
	(via
		(at 377.436634 -222.761556)
		(size 0.4572)
		(drill 0.2032)
		(layers "F.Cu" "B.Cu")
		(net "GND")
	)
	(via
		(at 120.678448 -279.150318)
		(size 0.4572)
		(drill 0.2032)
		(layers "F.Cu" "B.Cu")
		(net "GND")
	)
	(via
		(at 159.321246 -409.396184)
		(size 0.4572)
		(drill 0.254)
		(layers "F.Cu" "B.Cu")
		(net "GND")
	)
	(via
		(at 209.281014 -226.216718)
		(size 0.4572)
		(drill 0.2032)
		(layers "F.Cu" "B.Cu")
		(net "GND")
	)
	(via
		(at 109.980984 -395.813788)
		(size 0.508)
		(drill 0.254)
		(layers "F.Cu" "B.Cu")
		(net "GND")
	)
	(via
		(at 33.767014 -211.766658)
		(size 0.4572)
		(drill 0.2032)
		(layers "F.Cu" "B.Cu")
		(net "GND")
	)
	(via
		(at 63.098426 -400.224244)
		(size 0.4572)
		(drill 0.254)
		(layers "F.Cu" "B.Cu")
		(net "GND")
	)
	(via
		(at 254.975614 -234.716574)
		(size 0.4572)
		(drill 0.2032)
		(layers "F.Cu" "B.Cu")
		(net "GND")
	)
	(via
		(at 447.467482 -308.666642)
		(size 0.4572)
		(drill 0.2032)
		(layers "F.Cu" "B.Cu")
		(net "GND")
	)
	(via
		(at 268.104112 -62.615572)
		(size 0.508)
		(drill 0.254)
		(layers "F.Cu" "B.Cu")
		(net "GND")
	)
	(via
		(at 378.956062 -259.616956)
		(size 0.4572)
		(drill 0.2032)
		(layers "F.Cu" "B.Cu")
		(net "GND")
	)
	(via
		(at 111.17072 -218.691968)
		(size 0.4572)
		(drill 0.2032)
		(layers "F.Cu" "B.Cu")
		(net "GND")
	)
	(via
		(at 110.235746 -326.836532)
		(size 0.508)
		(drill 0.254)
		(layers "F.Cu" "B.Cu")
		(net "GND")
	)
	(via
		(at 419.735254 -238.116618)
		(size 0.4572)
		(drill 0.2032)
		(layers "F.Cu" "B.Cu")
		(net "GND")
	)
	(via
		(at 412.20263 -238.116618)
		(size 0.4572)
		(drill 0.2032)
		(layers "F.Cu" "B.Cu")
		(net "GND")
	)
	(via
		(at 67.42049 -403.249892)
		(size 0.4572)
		(drill 0.254)
		(layers "F.Cu" "B.Cu")
		(net "GND")
	)
	(via
		(at 100.619306 -326.823832)
		(size 0.508)
		(drill 0.254)
		(layers "F.Cu" "B.Cu")
		(net "GND")
	)
	(via
		(at 44.754546 -227.066602)
		(size 0.4572)
		(drill 0.2032)
		(layers "F.Cu" "B.Cu")
		(net "GND")
	)
	(via
		(at 197.637146 -223.666558)
		(size 0.4572)
		(drill 0.2032)
		(layers "F.Cu" "B.Cu")
		(net "GND")
	)
	(via
		(at 129.026412 -233.34218)
		(size 0.4572)
		(drill 0.2032)
		(layers "F.Cu" "B.Cu")
		(net "GND")
	)
	(via
		(at 261.285482 -303.566576)
		(size 0.4572)
		(drill 0.2032)
		(layers "F.Cu" "B.Cu")
		(net "GND")
	)
	(via
		(at 128.28397 -352.450654)
		(size 0.508)
		(drill 0.254)
		(layers "F.Cu" "B.Cu")
		(net "GND")
	)
	(via
		(at 290.227766 -360.83621)
		(size 0.49022)
		(drill 0.254)
		(layers "F.Cu" "B.Cu")
		(net "GND")
	)
	(via
		(at 351.122234 -219.506038)
		(size 0.4572)
		(drill 0.2032)
		(layers "F.Cu" "B.Cu")
		(net "GND")
	)
	(via
		(at 41.310814 -277.216616)
		(size 0.4572)
		(drill 0.2032)
		(layers "F.Cu" "B.Cu")
		(net "GND")
	)
	(via
		(at 427.045882 -286.56661)
		(size 0.4572)
		(drill 0.2032)
		(layers "F.Cu" "B.Cu")
		(net "GND")
	)
	(via
		(at 43.520614 -210.066636)
		(size 0.4572)
		(drill 0.2032)
		(layers "F.Cu" "B.Cu")
		(net "GND")
	)
	(via
		(at 238.940086 -116.951252)
		(size 0.508)
		(drill 0.254)
		(layers "F.Cu" "B.Cu")
		(net "GND")
	)
	(via
		(at 262.519414 -260.21665)
		(size 0.4572)
		(drill 0.2032)
		(layers "F.Cu" "B.Cu")
		(net "GND")
	)
	(via
		(at 134.195566 -237.411514)
		(size 0.4572)
		(drill 0.2032)
		(layers "F.Cu" "B.Cu")
		(net "GND")
	)
	(via
		(at 347.127068 -332.570074)
		(size 0.49022)
		(drill 0.254)
		(layers "F.Cu" "B.Cu")
		(net "GND")
	)
	(via
		(at 380.835662 -282.405836)
		(size 0.4572)
		(drill 0.2032)
		(layers "F.Cu" "B.Cu")
		(net "GND")
	)
	(via
		(at 287.98012 -393.776454)
		(size 0.508)
		(drill 0.254)
		(layers "F.Cu" "B.Cu")
		(net "GND")
	)
	(via
		(at 212.724746 -240.666778)
		(size 0.4572)
		(drill 0.2032)
		(layers "F.Cu" "B.Cu")
		(net "GND")
	)
	(via
		(at 333.845662 -259.616956)
		(size 0.4318)
		(drill 0.2032)
		(layers "F.Cu" "B.Cu")
		(net "GND")
	)
	(via
		(at 377.546362 -283.219906)
		(size 0.4572)
		(drill 0.2032)
		(layers "F.Cu" "B.Cu")
		(net "GND")
	)
	(via
		(at 410.35732 -167.071548)
		(size 0.508)
		(drill 0.254)
		(layers "F.Cu" "B.Cu")
		(net "GND")
	)
	(via
		(at 409.748482 -295.916604)
		(size 0.4572)
		(drill 0.2032)
		(layers "F.Cu" "B.Cu")
		(net "GND")
	)
	(via
		(at 432.379882 -261.066788)
		(size 0.4572)
		(drill 0.2032)
		(layers "F.Cu" "B.Cu")
		(net "GND")
	)
	(via
		(at 62.267846 -208.366614)
		(size 0.4572)
		(drill 0.2032)
		(layers "F.Cu" "B.Cu")
		(net "GND")
	)
	(via
		(at 325.250048 -437.34736)
		(size 0.4572)
		(drill 0.2032)
		(layers "F.Cu" "B.Cu")
		(net "GND")
	)
	(via
		(at 381.673862 -404.51786)
		(size 0.4572)
		(drill 0.254)
		(layers "F.Cu" "B.Cu")
		(net "GND")
	)
	(via
		(at 417.292282 -264.466578)
		(size 0.4572)
		(drill 0.2032)
		(layers "F.Cu" "B.Cu")
		(net "GND")
	)
	(via
		(at 341.39632 -332.363826)
		(size 0.508)
		(drill 0.254)
		(layers "F.Cu" "B.Cu")
		(net "GND")
	)
	(via
		(at 400.24685 -12.37488)
		(size 0.508)
		(drill 0.254)
		(layers "F.Cu" "B.Cu")
		(net "GND")
	)
	(via
		(at 413.832548 -354.182172)
		(size 0.508)
		(drill 0.254)
		(layers "F.Cu" "B.Cu")
		(net "GND")
	)
	(via
		(at 422.945814 -244.916706)
		(size 0.4572)
		(drill 0.2032)
		(layers "F.Cu" "B.Cu")
		(net "GND")
	)
	(via
		(at 86.250018 -437.34736)
		(size 0.4572)
		(drill 0.2032)
		(layers "F.Cu" "B.Cu")
		(net "GND")
	)
	(via
		(at 352.334322 -175.312832)
		(size 0.508)
		(drill 0.254)
		(layers "F.Cu" "B.Cu")
		(net "GND")
	)
	(via
		(at 66.367914 -235.566712)
		(size 0.4572)
		(drill 0.2032)
		(layers "F.Cu" "B.Cu")
		(net "GND")
	)
	(via
		(at 114.459766 -229.272846)
		(size 0.4572)
		(drill 0.2032)
		(layers "F.Cu" "B.Cu")
		(net "GND")
	)
	(via
		(at 216.824814 -241.516662)
		(size 0.4572)
		(drill 0.2032)
		(layers "F.Cu" "B.Cu")
		(net "GND")
	)
	(via
		(at 348.882716 -279.150318)
		(size 0.4572)
		(drill 0.2032)
		(layers "F.Cu" "B.Cu")
		(net "GND")
	)
	(via
		(at 127.616966 -242.294918)
		(size 0.4572)
		(drill 0.2032)
		(layers "F.Cu" "B.Cu")
		(net "GND")
	)
	(via
		(at 457.221082 -294.216582)
		(size 0.4572)
		(drill 0.2032)
		(layers "F.Cu" "B.Cu")
		(net "GND")
	)
	(via
		(at 462.555082 -289.966654)
		(size 0.4572)
		(drill 0.2032)
		(layers "F.Cu" "B.Cu")
		(net "GND")
	)
	(via
		(at 51.072034 -358.691942)
		(size 0.508)
		(drill 0.254)
		(layers "F.Cu" "B.Cu")
		(net "GND")
	)
	(via
		(at 122.088148 -281.59202)
		(size 0.4572)
		(drill 0.2032)
		(layers "F.Cu" "B.Cu")
		(net "GND")
	)
	(via
		(at 179.35575 -115.775486)
		(size 0.4572)
		(drill 0.254)
		(layers "F.Cu" "B.Cu")
		(net "GND")
	)
	(via
		(at 137.124948 -283.219906)
		(size 0.4572)
		(drill 0.2032)
		(layers "F.Cu" "B.Cu")
		(net "GND")
	)
	(via
		(at 455.011282 -222.816674)
		(size 0.4572)
		(drill 0.2032)
		(layers "F.Cu" "B.Cu")
		(net "GND")
	)
	(via
		(at 327.250044 -427.851316)
		(size 0.4572)
		(drill 0.2032)
		(layers "F.Cu" "B.Cu")
		(net "GND")
	)
	(via
		(at 299.004482 -305.266598)
		(size 0.4572)
		(drill 0.2032)
		(layers "F.Cu" "B.Cu")
		(net "GND")
	)
	(via
		(at 300.022514 -311.216802)
		(size 0.4572)
		(drill 0.2032)
		(layers "F.Cu" "B.Cu")
		(net "GND")
	)
	(via
		(at 78.053438 -400.858228)
		(size 0.4064)
		(drill 0.2032)
		(layers "F.Cu" "B.Cu")
		(net "GND")
	)
	(via
		(at 26.223214 -288.266632)
		(size 0.4572)
		(drill 0.2032)
		(layers "F.Cu" "B.Cu")
		(net "GND")
	)
	(via
		(at 187.883546 -236.416596)
		(size 0.4572)
		(drill 0.2032)
		(layers "F.Cu" "B.Cu")
		(net "GND")
	)
	(via
		(at 99.422966 -237.411514)
		(size 0.4572)
		(drill 0.2032)
		(layers "F.Cu" "B.Cu")
		(net "GND")
	)
	(via
		(at 134.305548 -266.941808)
		(size 0.4572)
		(drill 0.2032)
		(layers "F.Cu" "B.Cu")
		(net "GND")
	)
	(via
		(at 24.332946 -278.066754)
		(size 0.4572)
		(drill 0.2032)
		(layers "F.Cu" "B.Cu")
		(net "GND")
	)
	(via
		(at 413.192214 -270.416782)
		(size 0.4572)
		(drill 0.2032)
		(layers "F.Cu" "B.Cu")
		(net "GND")
	)
	(via
		(at 127.726948 -273.453098)
		(size 0.4572)
		(drill 0.2032)
		(layers "F.Cu" "B.Cu")
		(net "GND")
	)
	(via
		(at 117.397784 -297.19778)
		(size 0.508)
		(drill 0.254)
		(layers "F.Cu" "B.Cu")
		(net "GND")
	)
	(via
		(at 49.40681 -156.827982)
		(size 0.508)
		(drill 0.254)
		(layers "F.Cu" "B.Cu")
		(net "GND")
	)
	(via
		(at 84.250022 -425.547282)
		(size 0.4572)
		(drill 0.2032)
		(layers "F.Cu" "B.Cu")
		(net "GND")
	)
	(via
		(at 201.737214 -275.516594)
		(size 0.4572)
		(drill 0.2032)
		(layers "F.Cu" "B.Cu")
		(net "GND")
	)
	(via
		(at 56.83885 -154.465274)
		(size 0.49022)
		(drill 0.254)
		(layers "F.Cu" "B.Cu")
		(net "GND")
	)
	(via
		(at 130.345942 -103.81996)
		(size 0.508)
		(drill 0.254)
		(layers "F.Cu" "B.Cu")
		(net "GND")
	)
	(via
		(at 29.666946 -261.916672)
		(size 0.4572)
		(drill 0.2032)
		(layers "F.Cu" "B.Cu")
		(net "GND")
	)
	(via
		(at 274.163282 -277.216616)
		(size 0.4572)
		(drill 0.2032)
		(layers "F.Cu" "B.Cu")
		(net "GND")
	)
	(via
		(at 277.607014 -273.816572)
		(size 0.4572)
		(drill 0.2032)
		(layers "F.Cu" "B.Cu")
		(net "GND")
	)
	(via
		(at 187.14466 -10.117328)
		(size 0.508)
		(drill 0.254)
		(layers "F.Cu" "B.Cu")
		(net "GND")
	)
	(via
		(at 161.78784 -131.064508)
		(size 0.508)
		(drill 0.254)
		(layers "F.Cu" "B.Cu")
		(net "GND")
	)
	(via
		(at 121.508012 -239.853216)
		(size 0.4572)
		(drill 0.2032)
		(layers "F.Cu" "B.Cu")
		(net "GND")
	)
	(via
		(at 439.923682 -291.666676)
		(size 0.4572)
		(drill 0.2032)
		(layers "F.Cu" "B.Cu")
		(net "GND")
	)
	(via
		(at 153.613866 -107.660948)
		(size 0.508)
		(drill 0.254)
		(layers "F.Cu" "B.Cu")
		(net "GND")
	)
	(via
		(at 287.360614 -206.666592)
		(size 0.4572)
		(drill 0.2032)
		(layers "F.Cu" "B.Cu")
		(net "GND")
	)
	(via
		(at 164.188902 -407.638504)
		(size 0.4572)
		(drill 0.254)
		(layers "F.Cu" "B.Cu")
		(net "GND")
	)
	(via
		(at 92.844366 -237.411514)
		(size 0.4572)
		(drill 0.2032)
		(layers "F.Cu" "B.Cu")
		(net "GND")
	)
	(via
		(at 425.607734 -367.0681)
		(size 0.508)
		(drill 0.254)
		(layers "F.Cu" "B.Cu")
		(net "GND")
	)
	(via
		(at 328.64044 -14.811248)
		(size 0.508)
		(drill 0.254)
		(layers "F.Cu" "B.Cu")
		(net "GND")
	)
	(via
		(at 257.185414 -220.266768)
		(size 0.4572)
		(drill 0.2032)
		(layers "F.Cu" "B.Cu")
		(net "GND")
	)
	(via
		(at 314.092082 -194.766692)
		(size 0.4572)
		(drill 0.2032)
		(layers "F.Cu" "B.Cu")
		(net "GND")
	)
	(via
		(at 72.288146 -400.224244)
		(size 0.4572)
		(drill 0.254)
		(layers "F.Cu" "B.Cu")
		(net "GND")
	)
	(via
		(at 62.051946 -229.616762)
		(size 0.4572)
		(drill 0.2032)
		(layers "F.Cu" "B.Cu")
		(net "GND")
	)
	(via
		(at 204.456284 -323.434456)
		(size 0.4572)
		(drill 0.2032)
		(layers "F.Cu" "B.Cu")
		(net "GND")
	)
	(via
		(at 302.448214 -289.11677)
		(size 0.4572)
		(drill 0.2032)
		(layers "F.Cu" "B.Cu")
		(net "GND")
	)
	(via
		(at 190.093346 -268.71676)
		(size 0.4572)
		(drill 0.2032)
		(layers "F.Cu" "B.Cu")
		(net "GND")
	)
	(via
		(at 299.004482 -235.566712)
		(size 0.4572)
		(drill 0.2032)
		(layers "F.Cu" "B.Cu")
		(net "GND")
	)
	(via
		(at 54.333648 -164.86759)
		(size 0.49022)
		(drill 0.254)
		(layers "F.Cu" "B.Cu")
		(net "GND")
	)
	(via
		(at 121.303542 -409.396184)
		(size 0.4572)
		(drill 0.254)
		(layers "F.Cu" "B.Cu")
		(net "GND")
	)
	(via
		(at 300.637702 -423.954448)
		(size 0.508)
		(drill 0.254)
		(layers "F.Cu" "B.Cu")
		(net "GND")
	)
	(via
		(at 46.964346 -214.316564)
		(size 0.4572)
		(drill 0.2032)
		(layers "F.Cu" "B.Cu")
		(net "GND")
	)
	(via
		(at 11.135614 -305.266598)
		(size 0.4572)
		(drill 0.2032)
		(layers "F.Cu" "B.Cu")
		(net "GND")
	)
	(via
		(at 221.1578 -100.23348)
		(size 0.508)
		(drill 0.254)
		(layers "F.Cu" "B.Cu")
		(net "GND")
	)
	(via
		(at 235.488988 -421.99052)
		(size 0.508)
		(drill 0.254)
		(layers "F.Cu" "B.Cu")
		(net "GND")
	)
	(via
		(at 424.836082 -295.916604)
		(size 0.4572)
		(drill 0.2032)
		(layers "F.Cu" "B.Cu")
		(net "GND")
	)
	(via
		(at 132.785612 -231.714548)
		(size 0.4572)
		(drill 0.2032)
		(layers "F.Cu" "B.Cu")
		(net "GND")
	)
	(via
		(at 58.23077 -403.249892)
		(size 0.4572)
		(drill 0.254)
		(layers "F.Cu" "B.Cu")
		(net "GND")
	)
	(via
		(at 414.070292 -164.198554)
		(size 0.49022)
		(drill 0.254)
		(layers "F.Cu" "B.Cu")
		(net "GND")
	)
	(via
		(at 430.489614 -306.116736)
		(size 0.4572)
		(drill 0.2032)
		(layers "F.Cu" "B.Cu")
		(net "GND")
	)
	(via
		(at 16.789146 -250.016772)
		(size 0.4572)
		(drill 0.2032)
		(layers "F.Cu" "B.Cu")
		(net "GND")
	)
	(via
		(at 341.80018 -400.224244)
		(size 0.4572)
		(drill 0.254)
		(layers "F.Cu" "B.Cu")
		(net "GND")
	)
	(via
		(at 22.123146 -199.01662)
		(size 0.4572)
		(drill 0.2032)
		(layers "F.Cu" "B.Cu")
		(net "GND")
	)
	(via
		(at 157.708346 -306.116736)
		(size 0.4572)
		(drill 0.2032)
		(layers "F.Cu" "B.Cu")
		(net "GND")
	)
	(via
		(at 274.163282 -308.666642)
		(size 0.4572)
		(drill 0.2032)
		(layers "F.Cu" "B.Cu")
		(net "GND")
	)
	(via
		(at 464.764882 -297.616626)
		(size 0.4572)
		(drill 0.2032)
		(layers "F.Cu" "B.Cu")
		(net "GND")
	)
	(via
		(at 123.027694 -263.686544)
		(size 0.4572)
		(drill 0.2032)
		(layers "F.Cu" "B.Cu")
		(net "GND")
	)
	(via
		(at 88.72474 -277.522686)
		(size 0.4572)
		(drill 0.2032)
		(layers "F.Cu" "B.Cu")
		(net "GND")
	)
	(via
		(at 62.92088 -19.268948)
		(size 0.508)
		(drill 0.254)
		(layers "F.Cu" "B.Cu")
		(net "GND")
	)
	(via
		(at 57.659778 -351.06991)
		(size 0.6604)
		(drill 0.3302)
		(layers "F.Cu" "B.Cu")
		(net "GND")
	)
	(via
		(at 46.964346 -276.366732)
		(size 0.4572)
		(drill 0.2032)
		(layers "F.Cu" "B.Cu")
		(net "GND")
	)
	(via
		(at 187.883546 -281.466798)
		(size 0.4572)
		(drill 0.2032)
		(layers "F.Cu" "B.Cu")
		(net "GND")
	)
	(via
		(at 87.243158 -403.883876)
		(size 0.4064)
		(drill 0.2032)
		(layers "F.Cu" "B.Cu")
		(net "GND")
	)
	(via
		(at 202.84948 -79.444342)
		(size 0.508)
		(drill 0.254)
		(layers "F.Cu" "B.Cu")
		(net "GND")
	)
	(via
		(at 281.707082 -262.76681)
		(size 0.4572)
		(drill 0.2032)
		(layers "F.Cu" "B.Cu")
		(net "GND")
	)
	(via
		(at 460.664814 -283.166566)
		(size 0.4572)
		(drill 0.2032)
		(layers "F.Cu" "B.Cu")
		(net "GND")
	)
	(via
		(at 447.467482 -269.566644)
		(size 0.4572)
		(drill 0.2032)
		(layers "F.Cu" "B.Cu")
		(net "GND")
	)
	(via
		(at 394.349986 -435.0512)
		(size 0.4572)
		(drill 0.2032)
		(layers "F.Cu" "B.Cu")
		(net "GND")
	)
	(via
		(at 366.738662 -274.266914)
		(size 0.4572)
		(drill 0.2032)
		(layers "F.Cu" "B.Cu")
		(net "GND")
	)
	(via
		(at 153.256996 -17.655032)
		(size 0.508)
		(drill 0.254)
		(layers "F.Cu" "B.Cu")
		(net "GND")
	)
	(via
		(at 467.535514 -337.68538)
		(size 0.508)
		(drill 0.254)
		(layers "F.Cu" "B.Cu")
		(net "GND")
	)
	(via
		(at 412.953962 -236.416596)
		(size 0.4572)
		(drill 0.2032)
		(layers "F.Cu" "B.Cu")
		(net "GND")
	)
	(via
		(at 100.362766 -242.294918)
		(size 0.4572)
		(drill 0.2032)
		(layers "F.Cu" "B.Cu")
		(net "GND")
	)
	(via
		(at 153.34996 -426.54728)
		(size 0.4572)
		(drill 0.2032)
		(layers "F.Cu" "B.Cu")
		(net "GND")
	)
	(via
		(at 356.373684 -255.745996)
		(size 0.4572)
		(drill 0.2032)
		(layers "F.Cu" "B.Cu")
		(net "GND")
	)
	(via
		(at 305.0413 -401.492212)
		(size 0.4572)
		(drill 0.254)
		(layers "F.Cu" "B.Cu")
		(net "GND")
	)
	(via
		(at 279.816814 -251.716794)
		(size 0.4572)
		(drill 0.2032)
		(layers "F.Cu" "B.Cu")
		(net "GND")
	)
	(via
		(at 187.883546 -278.066754)
		(size 0.4572)
		(drill 0.2032)
		(layers "F.Cu" "B.Cu")
		(net "GND")
	)
	(via
		(at 427.602904 -120.238012)
		(size 0.508)
		(drill 0.254)
		(layers "F.Cu" "B.Cu")
		(net "GND")
	)
	(via
		(at 175.005746 -298.466764)
		(size 0.4572)
		(drill 0.2032)
		(layers "F.Cu" "B.Cu")
		(net "GND")
	)
	(via
		(at 104.275128 -292.948614)
		(size 0.508)
		(drill 0.254)
		(layers "F.Cu" "B.Cu")
		(net "GND")
	)
	(via
		(at 432.379882 -310.366664)
		(size 0.4572)
		(drill 0.2032)
		(layers "F.Cu" "B.Cu")
		(net "GND")
	)
	(via
		(at 84.20481 -338.303616)
		(size 0.508)
		(drill 0.254)
		(layers "F.Cu" "B.Cu")
		(net "GND")
	)
	(via
		(at 95.645478 -331.776832)
		(size 0.49022)
		(drill 0.254)
		(layers "F.Cu" "B.Cu")
		(net "GND")
	)
	(via
		(at 439.923682 -266.1666)
		(size 0.4572)
		(drill 0.2032)
		(layers "F.Cu" "B.Cu")
		(net "GND")
	)
	(via
		(at 424.836082 -226.216718)
		(size 0.4572)
		(drill 0.2032)
		(layers "F.Cu" "B.Cu")
		(net "GND")
	)
	(via
		(at 340.541356 -401.492212)
		(size 0.4572)
		(drill 0.254)
		(layers "F.Cu" "B.Cu")
		(net "GND")
	)
	(via
		(at 180.339746 -306.116736)
		(size 0.4572)
		(drill 0.2032)
		(layers "F.Cu" "B.Cu")
		(net "GND")
	)
	(via
		(at 61.250068 -430.147222)
		(size 0.4572)
		(drill 0.2032)
		(layers "F.Cu" "B.Cu")
		(net "GND")
	)
	(via
		(at 155.349956 -436.347362)
		(size 0.4572)
		(drill 0.2032)
		(layers "F.Cu" "B.Cu")
		(net "GND")
	)
	(via
		(at 374.61698 -232.528364)
		(size 0.4572)
		(drill 0.2032)
		(layers "F.Cu" "B.Cu")
		(net "GND")
	)
	(via
		(at 92.651326 -330.202032)
		(size 0.508)
		(drill 0.254)
		(layers "F.Cu" "B.Cu")
		(net "GND")
	)
	(via
		(at 131.015994 -256.361438)
		(size 0.4572)
		(drill 0.2032)
		(layers "F.Cu" "B.Cu")
		(net "GND")
	)
	(via
		(at 112.626902 -331.776832)
		(size 0.49022)
		(drill 0.254)
		(layers "F.Cu" "B.Cu")
		(net "GND")
	)
	(via
		(at 180.339746 -244.916706)
		(size 0.4572)
		(drill 0.2032)
		(layers "F.Cu" "B.Cu")
		(net "GND")
	)
	(via
		(at 283.916882 -275.516594)
		(size 0.4572)
		(drill 0.2032)
		(layers "F.Cu" "B.Cu")
		(net "GND")
	)
	(via
		(at 358.244902 -292.955726)
		(size 0.508)
		(drill 0.254)
		(layers "F.Cu" "B.Cu")
		(net "GND")
	)
	(via
		(at 13.345414 -202.416664)
		(size 0.4572)
		(drill 0.2032)
		(layers "F.Cu" "B.Cu")
		(net "GND")
	)
	(via
		(at 94.364048 -282.405836)
		(size 0.4572)
		(drill 0.2032)
		(layers "F.Cu" "B.Cu")
		(net "GND")
	)
	(via
		(at 374.038368 -334.45323)
		(size 0.508)
		(drill 0.254)
		(layers "F.Cu" "B.Cu")
		(net "GND")
	)
	(via
		(at 432.379882 -294.216582)
		(size 0.4572)
		(drill 0.2032)
		(layers "F.Cu" "B.Cu")
		(net "GND")
	)
	(via
		(at 86.265766 -245.55069)
		(size 0.4572)
		(drill 0.2032)
		(layers "F.Cu" "B.Cu")
		(net "GND")
	)
	(via
		(at 39.420546 -315.46673)
		(size 0.4572)
		(drill 0.2032)
		(layers "F.Cu" "B.Cu")
		(net "GND")
	)
	(via
		(at 356.870762 -278.336502)
		(size 0.4572)
		(drill 0.2032)
		(layers "F.Cu" "B.Cu")
		(net "GND")
	)
	(via
		(at 46.964346 -313.766708)
		(size 0.4572)
		(drill 0.2032)
		(layers "F.Cu" "B.Cu")
		(net "GND")
	)
	(via
		(at 89.084658 -214.622634)
		(size 0.4572)
		(drill 0.2032)
		(layers "F.Cu" "B.Cu")
		(net "GND")
	)
	(via
		(at 132.785866 -220.319854)
		(size 0.4572)
		(drill 0.2032)
		(layers "F.Cu" "B.Cu")
		(net "GND")
	)
	(via
		(at 467.679278 -38.456108)
		(size 0.508)
		(drill 0.254)
		(layers "F.Cu" "B.Cu")
		(net "GND")
	)
	(via
		(at 76.973938 -20.160742)
		(size 0.508)
		(drill 0.254)
		(layers "F.Cu" "B.Cu")
		(net "GND")
	)
	(via
		(at 334.205834 -227.64496)
		(size 0.4572)
		(drill 0.2032)
		(layers "F.Cu" "B.Cu")
		(net "GND")
	)
	(via
		(at 16.789146 -248.31675)
		(size 0.4572)
		(drill 0.2032)
		(layers "F.Cu" "B.Cu")
		(net "GND")
	)
	(via
		(at 278.294846 -416.27425)
		(size 0.508)
		(drill 0.254)
		(layers "F.Cu" "B.Cu")
		(net "GND")
	)
	(via
		(at 47.360078 -97.808034)
		(size 0.508)
		(drill 0.254)
		(layers "F.Cu" "B.Cu")
		(net "GND")
	)
	(via
		(at 305.92268 -49.621948)
		(size 0.508)
		(drill 0.254)
		(layers "F.Cu" "B.Cu")
		(net "GND")
	)
	(via
		(at 332.61046 -404.51786)
		(size 0.4572)
		(drill 0.254)
		(layers "F.Cu" "B.Cu")
		(net "GND")
	)
	(via
		(at 277.607014 -281.466798)
		(size 0.4572)
		(drill 0.2032)
		(layers "F.Cu" "B.Cu")
		(net "GND")
	)
	(via
		(at 168.510966 -406.370536)
		(size 0.4572)
		(drill 0.254)
		(layers "F.Cu" "B.Cu")
		(net "GND")
	)
	(via
		(at 408.05227 -285.667196)
		(size 0.4572)
		(drill 0.2032)
		(layers "F.Cu" "B.Cu")
		(net "GND")
	)
	(via
		(at 367.208562 -276.708616)
		(size 0.4572)
		(drill 0.2032)
		(layers "F.Cu" "B.Cu")
		(net "GND")
	)
	(via
		(at 311.882282 -258.516628)
		(size 0.4572)
		(drill 0.2032)
		(layers "F.Cu" "B.Cu")
		(net "GND")
	)
	(via
		(at 368.913664 -259.74929)
		(size 0.4572)
		(drill 0.2032)
		(layers "F.Cu" "B.Cu")
		(net "GND")
	)
	(via
		(at 134.349998 -429.147224)
		(size 0.4572)
		(drill 0.2032)
		(layers "F.Cu" "B.Cu")
		(net "GND")
	)
	(via
		(at 195.427346 -268.71676)
		(size 0.4572)
		(drill 0.2032)
		(layers "F.Cu" "B.Cu")
		(net "GND")
	)
	(via
		(at 309.992014 -258.516628)
		(size 0.4572)
		(drill 0.2032)
		(layers "F.Cu" "B.Cu")
		(net "GND")
	)
	(via
		(at 22.468586 -383.567178)
		(size 0.508)
		(drill 0.254)
		(layers "F.Cu" "B.Cu")
		(net "GND")
	)
	(via
		(at 439.923682 -303.566576)
		(size 0.4572)
		(drill 0.2032)
		(layers "F.Cu" "B.Cu")
		(net "GND")
	)
	(via
		(at 306.548282 -269.566644)
		(size 0.4572)
		(drill 0.2032)
		(layers "F.Cu" "B.Cu")
		(net "GND")
	)
	(via
		(at 354.003864 -254.014986)
		(size 0.4572)
		(drill 0.2032)
		(layers "F.Cu" "B.Cu")
		(net "GND")
	)
	(via
		(at 11.135614 -269.566644)
		(size 0.4572)
		(drill 0.2032)
		(layers "F.Cu" "B.Cu")
		(net "GND")
	)
	(via
		(at 337.025234 -224.389442)
		(size 0.4572)
		(drill 0.2032)
		(layers "F.Cu" "B.Cu")
		(net "GND")
	)
	(via
		(at 179.105814 -228.766624)
		(size 0.4572)
		(drill 0.2032)
		(layers "F.Cu" "B.Cu")
		(net "GND")
	)
	(via
		(at 299.004482 -198.166736)
		(size 0.4572)
		(drill 0.2032)
		(layers "F.Cu" "B.Cu")
		(net "GND")
	)
	(via
		(at 427.045882 -269.566644)
		(size 0.4572)
		(drill 0.2032)
		(layers "F.Cu" "B.Cu")
		(net "GND")
	)
	(via
		(at 358.280462 -285.661354)
		(size 0.4572)
		(drill 0.2032)
		(layers "F.Cu" "B.Cu")
		(net "GND")
	)
	(via
		(at 452.628 -31.35757)
		(size 0.508)
		(drill 0.254)
		(layers "F.Cu" "B.Cu")
		(net "GND")
	)
	(via
		(at 359.66908 -55.884572)
		(size 0.508)
		(drill 0.254)
		(layers "F.Cu" "B.Cu")
		(net "GND")
	)
	(via
		(at 75.254358 -410.030168)
		(size 0.4064)
		(drill 0.2032)
		(layers "F.Cu" "B.Cu")
		(net "GND")
	)
	(via
		(at 272.273014 -296.766742)
		(size 0.4572)
		(drill 0.2032)
		(layers "F.Cu" "B.Cu")
		(net "GND")
	)
	(via
		(at 97.543112 -235.783882)
		(size 0.4572)
		(drill 0.2032)
		(layers "F.Cu" "B.Cu")
		(net "GND")
	)
	(via
		(at 164.018214 -233.86669)
		(size 0.4572)
		(drill 0.2032)
		(layers "F.Cu" "B.Cu")
		(net "GND")
	)
	(via
		(at 153.01722 -39.080948)
		(size 0.508)
		(drill 0.254)
		(layers "F.Cu" "B.Cu")
		(net "GND")
	)
	(via
		(at 302.637444 -359.482898)
		(size 0.508)
		(drill 0.254)
		(layers "F.Cu" "B.Cu")
		(net "GND")
	)
	(via
		(at 33.773618 -193.17335)
		(size 0.508)
		(drill 0.254)
		(layers "F.Cu" "B.Cu")
		(net "GND")
	)
	(via
		(at 46.964346 -250.016772)
		(size 0.4572)
		(drill 0.2032)
		(layers "F.Cu" "B.Cu")
		(net "GND")
	)
	(via
		(at 274.163282 -316.316614)
		(size 0.4572)
		(drill 0.2032)
		(layers "F.Cu" "B.Cu")
		(net "GND")
	)
	(via
		(at 134.775448 -287.28924)
		(size 0.4572)
		(drill 0.2032)
		(layers "F.Cu" "B.Cu")
		(net "GND")
	)
	(via
		(at 427.045882 -280.61666)
		(size 0.4572)
		(drill 0.2032)
		(layers "F.Cu" "B.Cu")
		(net "GND")
	)
	(via
		(at 40.788082 -18.502376)
		(size 0.508)
		(drill 0.254)
		(layers "F.Cu" "B.Cu")
		(net "GND")
	)
	(via
		(at 176.896014 -312.91657)
		(size 0.4572)
		(drill 0.2032)
		(layers "F.Cu" "B.Cu")
		(net "GND")
	)
	(via
		(at 62.051946 -210.916774)
		(size 0.4572)
		(drill 0.2032)
		(layers "F.Cu" "B.Cu")
		(net "GND")
	)
	(via
		(at 158.062422 -409.396184)
		(size 0.4572)
		(drill 0.254)
		(layers "F.Cu" "B.Cu")
		(net "GND")
	)
	(via
		(at 194.193414 -280.61666)
		(size 0.4572)
		(drill 0.2032)
		(layers "F.Cu" "B.Cu")
		(net "GND")
	)
	(via
		(at 272.273014 -197.316598)
		(size 0.4572)
		(drill 0.2032)
		(layers "F.Cu" "B.Cu")
		(net "GND")
	)
	(via
		(at 225.518726 -98.200972)
		(size 0.508)
		(drill 0.254)
		(layers "F.Cu" "B.Cu")
		(net "GND")
	)
	(via
		(at 202.87488 -148.681948)
		(size 0.508)
		(drill 0.254)
		(layers "F.Cu" "B.Cu")
		(net "GND")
	)
	(via
		(at 20.889214 -286.56661)
		(size 0.4572)
		(drill 0.2032)
		(layers "F.Cu" "B.Cu")
		(net "GND")
	)
	(via
		(at 205.180946 -229.616762)
		(size 0.4572)
		(drill 0.2032)
		(layers "F.Cu" "B.Cu")
		(net "GND")
	)
	(via
		(at 284.599888 -410.21254)
		(size 0.508)
		(drill 0.254)
		(layers "F.Cu" "B.Cu")
		(net "GND")
	)
	(via
		(at 365.219234 -234.15625)
		(size 0.4572)
		(drill 0.2032)
		(layers "F.Cu" "B.Cu")
		(net "GND")
	)
	(via
		(at 70.209918 -410.030168)
		(size 0.4064)
		(drill 0.2032)
		(layers "F.Cu" "B.Cu")
		(net "GND")
	)
	(via
		(at 340.290658 -48.450246)
		(size 0.4572)
		(drill 0.2032)
		(layers "F.Cu" "B.Cu")
		(net "GND")
	)
	(via
		(at 462.555082 -196.466714)
		(size 0.4572)
		(drill 0.2032)
		(layers "F.Cu" "B.Cu")
		(net "GND")
	)
	(via
		(at 374.257062 -269.38351)
		(size 0.4572)
		(drill 0.2032)
		(layers "F.Cu" "B.Cu")
		(net "GND")
	)
	(via
		(at 403.349968 -438.651396)
		(size 0.4572)
		(drill 0.2032)
		(layers "F.Cu" "B.Cu")
		(net "GND")
	)
	(via
		(at 84.386166 -234.15625)
		(size 0.4572)
		(drill 0.2032)
		(layers "F.Cu" "B.Cu")
		(net "GND")
	)
	(via
		(at 44.754546 -296.766742)
		(size 0.4572)
		(drill 0.2032)
		(layers "F.Cu" "B.Cu")
		(net "GND")
	)
	(via
		(at 128.785874 -400.858228)
		(size 0.4064)
		(drill 0.2032)
		(layers "F.Cu" "B.Cu")
		(net "GND")
	)
	(via
		(at 152.6667 -25.402032)
		(size 0.508)
		(drill 0.254)
		(layers "F.Cu" "B.Cu")
		(net "GND")
	)
	(via
		(at 62.051946 -244.916706)
		(size 0.4572)
		(drill 0.2032)
		(layers "F.Cu" "B.Cu")
		(net "GND")
	)
	(via
		(at 254.27051 -77.373988)
		(size 0.508)
		(drill 0.254)
		(layers "F.Cu" "B.Cu")
		(net "GND")
	)
	(via
		(at 304.122582 -288.266632)
		(size 0.4572)
		(drill 0.2032)
		(layers "F.Cu" "B.Cu")
		(net "GND")
	)
	(via
		(at 164.018214 -241.516662)
		(size 0.4572)
		(drill 0.2032)
		(layers "F.Cu" "B.Cu")
		(net "GND")
	)
	(via
		(at 187.883546 -203.266802)
		(size 0.4572)
		(drill 0.2032)
		(layers "F.Cu" "B.Cu")
		(net "GND")
	)
	(via
		(at 434.589682 -267.866622)
		(size 0.4572)
		(drill 0.2032)
		(layers "F.Cu" "B.Cu")
		(net "GND")
	)
	(via
		(at 164.22878 -310.366664)
		(size 0.4572)
		(drill 0.2032)
		(layers "F.Cu" "B.Cu")
		(net "GND")
	)
	(via
		(at 136.619742 -410.664152)
		(size 0.4572)
		(drill 0.254)
		(layers "F.Cu" "B.Cu")
		(net "GND")
	)
	(via
		(at 414.070292 -180.149754)
		(size 0.49022)
		(drill 0.254)
		(layers "F.Cu" "B.Cu")
		(net "GND")
	)
	(via
		(at 190.093346 -236.416596)
		(size 0.4572)
		(drill 0.2032)
		(layers "F.Cu" "B.Cu")
		(net "GND")
	)
	(via
		(at 385.894834 -235.783882)
		(size 0.4318)
		(drill 0.2032)
		(layers "F.Cu" "B.Cu")
		(net "GND")
	)
	(via
		(at 24.332946 -216.016586)
		(size 0.4572)
		(drill 0.2032)
		(layers "F.Cu" "B.Cu")
		(net "GND")
	)
	(via
		(at 127.726948 -278.336502)
		(size 0.4572)
		(drill 0.2032)
		(layers "F.Cu" "B.Cu")
		(net "GND")
	)
	(via
		(at 180.03393 -331.140054)
		(size 0.508)
		(drill 0.254)
		(layers "F.Cu" "B.Cu")
		(net "GND")
	)
	(via
		(at 347.002862 -287.28924)
		(size 0.4572)
		(drill 0.2032)
		(layers "F.Cu" "B.Cu")
		(net "GND")
	)
	(via
		(at 171.562014 -222.816674)
		(size 0.4572)
		(drill 0.2032)
		(layers "F.Cu" "B.Cu")
		(net "GND")
	)
	(via
		(at 85.905594 -280.778204)
		(size 0.4318)
		(drill 0.2032)
		(layers "F.Cu" "B.Cu")
		(net "GND")
	)
	(via
		(at 54.508146 -283.166566)
		(size 0.4572)
		(drill 0.2032)
		(layers "F.Cu" "B.Cu")
		(net "GND")
	)
	(via
		(at 127.256794 -284.033722)
		(size 0.4572)
		(drill 0.2032)
		(layers "F.Cu" "B.Cu")
		(net "GND")
	)
	(via
		(at 123.497594 -262.872474)
		(size 0.4572)
		(drill 0.2032)
		(layers "F.Cu" "B.Cu")
		(net "GND")
	)
	(via
		(at 417.292282 -266.1666)
		(size 0.4572)
		(drill 0.2032)
		(layers "F.Cu" "B.Cu")
		(net "GND")
	)
	(via
		(at 69.250052 -436.051198)
		(size 0.4572)
		(drill 0.2032)
		(layers "F.Cu" "B.Cu")
		(net "GND")
	)
	(via
		(at 392.637772 -19.759422)
		(size 0.508)
		(drill 0.254)
		(layers "F.Cu" "B.Cu")
		(net "GND")
	)
	(via
		(at 56.049672 -154.465274)
		(size 0.49022)
		(drill 0.254)
		(layers "F.Cu" "B.Cu")
		(net "GND")
	)
	(via
		(at 199.527414 -305.266598)
		(size 0.4572)
		(drill 0.2032)
		(layers "F.Cu" "B.Cu")
		(net "GND")
	)
	(via
		(at 38.015926 -183.30164)
		(size 0.508)
		(drill 0.254)
		(layers "F.Cu" "B.Cu")
		(net "GND")
	)
	(via
		(at 405.89962 -63.754508)
		(size 0.508)
		(drill 0.254)
		(layers "F.Cu" "B.Cu")
		(net "GND")
	)
	(via
		(at 427.538642 -6.586474)
		(size 0.508)
		(drill 0.254)
		(layers "F.Cu" "B.Cu")
		(net "GND")
	)
	(via
		(at 24.332946 -279.766776)
		(size 0.4572)
		(drill 0.2032)
		(layers "F.Cu" "B.Cu")
		(net "GND")
	)
	(via
		(at 281.707082 -205.816708)
		(size 0.4572)
		(drill 0.2032)
		(layers "F.Cu" "B.Cu")
		(net "GND")
	)
	(via
		(at 371.32768 -239.853216)
		(size 0.4572)
		(drill 0.2032)
		(layers "F.Cu" "B.Cu")
		(net "GND")
	)
	(via
		(at 343.14638 -409.396184)
		(size 0.4572)
		(drill 0.254)
		(layers "F.Cu" "B.Cu")
		(net "GND")
	)
	(via
		(at 145.349976 -430.147222)
		(size 0.4572)
		(drill 0.2032)
		(layers "F.Cu" "B.Cu")
		(net "GND")
	)
	(via
		(at 405.072596 -18.491454)
		(size 0.508)
		(drill 0.254)
		(layers "F.Cu" "B.Cu")
		(net "GND")
	)
	(via
		(at 276.373082 -215.166702)
		(size 0.4572)
		(drill 0.2032)
		(layers "F.Cu" "B.Cu")
		(net "GND")
	)
	(via
		(at 97.183194 -277.522432)
		(size 0.4572)
		(drill 0.2032)
		(layers "F.Cu" "B.Cu")
		(net "GND")
	)
	(via
		(at 52.191666 -407.638504)
		(size 0.4572)
		(drill 0.254)
		(layers "F.Cu" "B.Cu")
		(net "GND")
	)
	(via
		(at 342.304116 -256.361438)
		(size 0.4572)
		(drill 0.2032)
		(layers "F.Cu" "B.Cu")
		(net "GND")
	)
	(via
		(at 110.23092 -236.597698)
		(size 0.4572)
		(drill 0.2032)
		(layers "F.Cu" "B.Cu")
		(net "GND")
	)
	(via
		(at 385.065016 -283.219906)
		(size 0.4572)
		(drill 0.2032)
		(layers "F.Cu" "B.Cu")
		(net "GND")
	)
	(via
		(at 300.238414 -268.71676)
		(size 0.4572)
		(drill 0.2032)
		(layers "F.Cu" "B.Cu")
		(net "GND")
	)
	(via
		(at 382.35001 -435.0512)
		(size 0.4572)
		(drill 0.2032)
		(layers "F.Cu" "B.Cu")
		(net "GND")
	)
	(via
		(at 178.289204 -42.29989)
		(size 0.508)
		(drill 0.254)
		(layers "F.Cu" "B.Cu")
		(net "GND")
	)
	(via
		(at 172.795946 -270.416782)
		(size 0.4572)
		(drill 0.2032)
		(layers "F.Cu" "B.Cu")
		(net "GND")
	)
	(via
		(at 352.062034 -229.272846)
		(size 0.4572)
		(drill 0.2032)
		(layers "F.Cu" "B.Cu")
		(net "GND")
	)
	(via
		(at 386.944362 -278.336502)
		(size 0.4572)
		(drill 0.2032)
		(layers "F.Cu" "B.Cu")
		(net "GND")
	)
	(via
		(at 132.350002 -439.651394)
		(size 0.4572)
		(drill 0.2032)
		(layers "F.Cu" "B.Cu")
		(net "GND")
	)
	(via
		(at 140.349986 -434.899562)
		(size 0.4572)
		(drill 0.2032)
		(layers "F.Cu" "B.Cu")
		(net "GND")
	)
	(via
		(at 296.794682 -284.866588)
		(size 0.4572)
		(drill 0.2032)
		(layers "F.Cu" "B.Cu")
		(net "GND")
	)
	(via
		(at 171.562014 -228.766624)
		(size 0.4572)
		(drill 0.2032)
		(layers "F.Cu" "B.Cu")
		(net "GND")
	)
	(via
		(at 378.956062 -254.733552)
		(size 0.4572)
		(drill 0.2032)
		(layers "F.Cu" "B.Cu")
		(net "GND")
	)
	(via
		(at 447.467482 -196.466714)
		(size 0.4572)
		(drill 0.2032)
		(layers "F.Cu" "B.Cu")
		(net "GND")
	)
	(via
		(at 311.528968 -400.858228)
		(size 0.4064)
		(drill 0.2032)
		(layers "F.Cu" "B.Cu")
		(net "GND")
	)
	(via
		(at 9.245346 -197.316598)
		(size 0.4572)
		(drill 0.2032)
		(layers "F.Cu" "B.Cu")
		(net "GND")
	)
	(via
		(at 87.063326 -330.166472)
		(size 0.508)
		(drill 0.254)
		(layers "F.Cu" "B.Cu")
		(net "GND")
	)
	(via
		(at 105.061766 -222.761556)
		(size 0.4572)
		(drill 0.2032)
		(layers "F.Cu" "B.Cu")
		(net "GND")
	)
	(via
		(at 2.764536 -254.430022)
		(size 0.508)
		(drill 0.254)
		(layers "F.Cu" "B.Cu")
		(net "GND")
	)
	(via
		(at 128.666748 -270.19758)
		(size 0.4572)
		(drill 0.2032)
		(layers "F.Cu" "B.Cu")
		(net "GND")
	)
	(via
		(at 455.011282 -269.566644)
		(size 0.4572)
		(drill 0.2032)
		(layers "F.Cu" "B.Cu")
		(net "GND")
	)
	(via
		(at 434.082952 -388.73303)
		(size 0.508)
		(drill 0.254)
		(layers "F.Cu" "B.Cu")
		(net "GND")
	)
	(via
		(at 277.607014 -206.666592)
		(size 0.4572)
		(drill 0.2032)
		(layers "F.Cu" "B.Cu")
		(net "GND")
	)
	(via
		(at 326.845168 -400.858228)
		(size 0.4064)
		(drill 0.2032)
		(layers "F.Cu" "B.Cu")
		(net "GND")
	)
	(via
		(at 129.606548 -268.569694)
		(size 0.4572)
		(drill 0.2032)
		(layers "F.Cu" "B.Cu")
		(net "GND")
	)
	(via
		(at 116.694458 -201.48677)
		(size 0.6604)
		(drill 0.3302)
		(layers "F.Cu" "B.Cu")
		(net "GND")
	)
	(via
		(at 438.033414 -236.416596)
		(size 0.4572)
		(drill 0.2032)
		(layers "F.Cu" "B.Cu")
		(net "GND")
	)
	(via
		(at 172.795946 -242.3668)
		(size 0.4572)
		(drill 0.2032)
		(layers "F.Cu" "B.Cu")
		(net "GND")
	)
	(via
		(at 424.836082 -264.466578)
		(size 0.4572)
		(drill 0.2032)
		(layers "F.Cu" "B.Cu")
		(net "GND")
	)
	(via
		(at 188.657484 -323.434456)
		(size 0.4572)
		(drill 0.2032)
		(layers "F.Cu" "B.Cu")
		(net "GND")
	)
	(via
		(at 165.252146 -304.416714)
		(size 0.4572)
		(drill 0.2032)
		(layers "F.Cu" "B.Cu")
		(net "GND")
	)
	(via
		(at 128.35001 -426.54728)
		(size 0.4572)
		(drill 0.2032)
		(layers "F.Cu" "B.Cu")
		(net "GND")
	)
	(via
		(at 24.332946 -273.816572)
		(size 0.4572)
		(drill 0.2032)
		(layers "F.Cu" "B.Cu")
		(net "GND")
	)
	(via
		(at 202.971146 -287.416748)
		(size 0.4572)
		(drill 0.2032)
		(layers "F.Cu" "B.Cu")
		(net "GND")
	)
	(via
		(at 264.729214 -197.316598)
		(size 0.4572)
		(drill 0.2032)
		(layers "F.Cu" "B.Cu")
		(net "GND")
	)
	(via
		(at 276.373082 -312.91657)
		(size 0.4572)
		(drill 0.2032)
		(layers "F.Cu" "B.Cu")
		(net "GND")
	)
	(via
		(at 190.093346 -290.816792)
		(size 0.4572)
		(drill 0.2032)
		(layers "F.Cu" "B.Cu")
		(net "GND")
	)
	(via
		(at 80.645254 -340.977728)
		(size 0.49022)
		(drill 0.254)
		(layers "F.Cu" "B.Cu")
		(net "GND")
	)
	(via
		(at 70.844918 -400.858228)
		(size 0.4064)
		(drill 0.2032)
		(layers "F.Cu" "B.Cu")
		(net "GND")
	)
	(via
		(at 33.767014 -219.41663)
		(size 0.4572)
		(drill 0.2032)
		(layers "F.Cu" "B.Cu")
		(net "GND")
	)
	(via
		(at 230.984044 -58.764932)
		(size 0.508)
		(drill 0.254)
		(layers "F.Cu" "B.Cu")
		(net "GND")
	)
	(via
		(at 13.345414 -312.91657)
		(size 0.4572)
		(drill 0.2032)
		(layers "F.Cu" "B.Cu")
		(net "GND")
	)
	(via
		(at 117.964458 -330.24572)
		(size 0.508)
		(drill 0.254)
		(layers "F.Cu" "B.Cu")
		(net "GND")
	)
	(via
		(at 427.045882 -282.316682)
		(size 0.4572)
		(drill 0.2032)
		(layers "F.Cu" "B.Cu")
		(net "GND")
	)
	(via
		(at 153.291794 -400.858228)
		(size 0.4064)
		(drill 0.2032)
		(layers "F.Cu" "B.Cu")
		(net "GND")
	)
	(via
		(at 48.854614 -232.166668)
		(size 0.4572)
		(drill 0.2032)
		(layers "F.Cu" "B.Cu")
		(net "GND")
	)
	(via
		(at 205.180946 -301.866808)
		(size 0.4572)
		(drill 0.2032)
		(layers "F.Cu" "B.Cu")
		(net "GND")
	)
	(via
		(at 355.931216 -273.453098)
		(size 0.4572)
		(drill 0.2032)
		(layers "F.Cu" "B.Cu")
		(net "GND")
	)
	(via
		(at 370.967762 -263.686544)
		(size 0.4572)
		(drill 0.2032)
		(layers "F.Cu" "B.Cu")
		(net "GND")
	)
	(via
		(at 328.242422 -36.363148)
		(size 0.508)
		(drill 0.254)
		(layers "F.Cu" "B.Cu")
		(net "GND")
	)
	(via
		(at 382.245616 -283.219906)
		(size 0.4572)
		(drill 0.2032)
		(layers "F.Cu" "B.Cu")
		(net "GND")
	)
	(via
		(at 388.349998 -431.29962)
		(size 0.4572)
		(drill 0.2032)
		(layers "F.Cu" "B.Cu")
		(net "GND")
	)
	(via
		(at 300.238414 -203.266802)
		(size 0.4572)
		(drill 0.2032)
		(layers "F.Cu" "B.Cu")
		(net "GND")
	)
	(via
		(at 128.133602 -337.692238)
		(size 0.49022)
		(drill 0.254)
		(layers "F.Cu" "B.Cu")
		(net "GND")
	)
	(via
		(at 259.075682 -297.616626)
		(size 0.4572)
		(drill 0.2032)
		(layers "F.Cu" "B.Cu")
		(net "GND")
	)
	(via
		(at 352.641662 -279.150318)
		(size 0.4572)
		(drill 0.2032)
		(layers "F.Cu" "B.Cu")
		(net "GND")
	)
	(via
		(at 270.063214 -251.716794)
		(size 0.4572)
		(drill 0.2032)
		(layers "F.Cu" "B.Cu")
		(net "GND")
	)
	(via
		(at 415.649918 -160.021778)
		(size 0.49022)
		(drill 0.254)
		(layers "F.Cu" "B.Cu")
		(net "GND")
	)
	(via
		(at 82.73669 -403.249892)
		(size 0.4572)
		(drill 0.254)
		(layers "F.Cu" "B.Cu")
		(net "GND")
	)
	(via
		(at 339.84438 -232.528364)
		(size 0.4572)
		(drill 0.2032)
		(layers "F.Cu" "B.Cu")
		(net "GND")
	)
	(via
		(at 331.881988 -44.221146)
		(size 0.4572)
		(drill 0.2032)
		(layers "F.Cu" "B.Cu")
		(net "GND")
	)
	(via
		(at 161.808414 -266.1666)
		(size 0.4572)
		(drill 0.2032)
		(layers "F.Cu" "B.Cu")
		(net "GND")
	)
	(via
		(at 169.352214 -264.466578)
		(size 0.4572)
		(drill 0.2032)
		(layers "F.Cu" "B.Cu")
		(net "GND")
	)
	(via
		(at 417.292282 -280.61666)
		(size 0.4572)
		(drill 0.2032)
		(layers "F.Cu" "B.Cu")
		(net "GND")
	)
	(via
		(at 209.281014 -247.466612)
		(size 0.4572)
		(drill 0.2032)
		(layers "F.Cu" "B.Cu")
		(net "GND")
	)
	(via
		(at 43.520614 -238.116618)
		(size 0.4572)
		(drill 0.2032)
		(layers "F.Cu" "B.Cu")
		(net "GND")
	)
	(via
		(at 141.10843 -34.12236)
		(size 0.508)
		(drill 0.254)
		(layers "F.Cu" "B.Cu")
		(net "GND")
	)
	(via
		(at 17.540732 -0.76454)
		(size 0.508)
		(drill 0.254)
		(layers "F.Cu" "B.Cu")
		(net "GND")
	)
	(via
		(at 102.50678 -98.773996)
		(size 0.508)
		(drill 0.254)
		(layers "F.Cu" "B.Cu")
		(net "GND")
	)
	(via
		(at 87.315294 -266.941808)
		(size 0.4318)
		(drill 0.2032)
		(layers "F.Cu" "B.Cu")
		(net "GND")
	)
	(via
		(at 319.25006 -429.147224)
		(size 0.4572)
		(drill 0.2032)
		(layers "F.Cu" "B.Cu")
		(net "GND")
	)
	(via
		(at 464.764882 -308.666642)
		(size 0.4572)
		(drill 0.2032)
		(layers "F.Cu" "B.Cu")
		(net "GND")
	)
	(via
		(at 132.895594 -287.28924)
		(size 0.4572)
		(drill 0.2032)
		(layers "F.Cu" "B.Cu")
		(net "GND")
	)
	(via
		(at 367.4364 -405.2316)
		(size 0.508)
		(drill 0.254)
		(layers "F.Cu" "B.Cu")
		(net "GND")
	)
	(via
		(at 129.831846 -342.764872)
		(size 0.508)
		(drill 0.254)
		(layers "F.Cu" "B.Cu")
		(net "GND")
	)
	(via
		(at 13.345414 -194.766692)
		(size 0.4572)
		(drill 0.2032)
		(layers "F.Cu" "B.Cu")
		(net "GND")
	)
	(via
		(at 100.942394 -259.616956)
		(size 0.4572)
		(drill 0.2032)
		(layers "F.Cu" "B.Cu")
		(net "GND")
	)
	(via
		(at 412.03245 -410.030168)
		(size 0.4064)
		(drill 0.2032)
		(layers "F.Cu" "B.Cu")
		(net "GND")
	)
	(via
		(at 281.707082 -219.41663)
		(size 0.4572)
		(drill 0.2032)
		(layers "F.Cu" "B.Cu")
		(net "GND")
	)
	(via
		(at 119.26189 -12.544552)
		(size 0.508)
		(drill 0.254)
		(layers "F.Cu" "B.Cu")
		(net "GND")
	)
	(via
		(at 413.192214 -204.96657)
		(size 0.4572)
		(drill 0.2032)
		(layers "F.Cu" "B.Cu")
		(net "GND")
	)
	(via
		(at 272.273014 -238.966756)
		(size 0.4572)
		(drill 0.2032)
		(layers "F.Cu" "B.Cu")
		(net "GND")
	)
	(via
		(at 262.519414 -296.766742)
		(size 0.4572)
		(drill 0.2032)
		(layers "F.Cu" "B.Cu")
		(net "GND")
	)
	(via
		(at 259.075682 -284.866588)
		(size 0.4572)
		(drill 0.2032)
		(layers "F.Cu" "B.Cu")
		(net "GND")
	)
	(via
		(at 353.581716 -275.8948)
		(size 0.4572)
		(drill 0.2032)
		(layers "F.Cu" "B.Cu")
		(net "GND")
	)
	(via
		(at 127.147066 -244.73662)
		(size 0.4572)
		(drill 0.2032)
		(layers "F.Cu" "B.Cu")
		(net "GND")
	)
	(via
		(at 375.3358 -60.076588)
		(size 0.508)
		(drill 0.254)
		(layers "F.Cu" "B.Cu")
		(net "GND")
	)
	(via
		(at 47.150782 -350.984058)
		(size 0.508)
		(drill 0.254)
		(layers "F.Cu" "B.Cu")
		(net "GND")
	)
	(via
		(at 306.548282 -194.766692)
		(size 0.4572)
		(drill 0.2032)
		(layers "F.Cu" "B.Cu")
		(net "GND")
	)
	(via
		(at 342.664034 -226.017328)
		(size 0.4572)
		(drill 0.2032)
		(layers "F.Cu" "B.Cu")
		(net "GND")
	)
	(via
		(at 175.005746 -270.416782)
		(size 0.4572)
		(drill 0.2032)
		(layers "F.Cu" "B.Cu")
		(net "GND")
	)
	(via
		(at 349.822262 -287.28924)
		(size 0.4572)
		(drill 0.2032)
		(layers "F.Cu" "B.Cu")
		(net "GND")
	)
	(via
		(at 257.185414 -242.3668)
		(size 0.4572)
		(drill 0.2032)
		(layers "F.Cu" "B.Cu")
		(net "GND")
	)
	(via
		(at 131.015994 -275.8948)
		(size 0.4572)
		(drill 0.2032)
		(layers "F.Cu" "B.Cu")
		(net "GND")
	)
	(via
		(at 128.03505 -58.740548)
		(size 0.508)
		(drill 0.254)
		(layers "F.Cu" "B.Cu")
		(net "GND")
	)
	(via
		(at 35.976814 -210.066636)
		(size 0.4572)
		(drill 0.2032)
		(layers "F.Cu" "B.Cu")
		(net "GND")
	)
	(via
		(at 309.992014 -272.116804)
		(size 0.4572)
		(drill 0.2032)
		(layers "F.Cu" "B.Cu")
		(net "GND")
	)
	(via
		(at 287.360614 -267.016738)
		(size 0.4572)
		(drill 0.2032)
		(layers "F.Cu" "B.Cu")
		(net "GND")
	)
	(via
		(at 299.004482 -275.516594)
		(size 0.4572)
		(drill 0.2032)
		(layers "F.Cu" "B.Cu")
		(net "GND")
	)
	(via
		(at 319.25006 -433.899564)
		(size 0.4572)
		(drill 0.2032)
		(layers "F.Cu" "B.Cu")
		(net "GND")
	)
	(via
		(at 415.402014 -195.616576)
		(size 0.4572)
		(drill 0.2032)
		(layers "F.Cu" "B.Cu")
		(net "GND")
	)
	(via
		(at 264.729214 -229.616762)
		(size 0.4572)
		(drill 0.2032)
		(layers "F.Cu" "B.Cu")
		(net "GND")
	)
	(via
		(at 151.349964 -431.451258)
		(size 0.4572)
		(drill 0.2032)
		(layers "F.Cu" "B.Cu")
		(net "GND")
	)
	(via
		(at 397.077438 -406.370536)
		(size 0.4572)
		(drill 0.254)
		(layers "F.Cu" "B.Cu")
		(net "GND")
	)
	(via
		(at 350.334834 -339.334602)
		(size 0.508)
		(drill 0.254)
		(layers "F.Cu" "B.Cu")
		(net "GND")
	)
	(via
		(at 129.393442 -339.114638)
		(size 0.49022)
		(drill 0.254)
		(layers "F.Cu" "B.Cu")
		(net "GND")
	)
	(via
		(at 344.183462 -287.28924)
		(size 0.4572)
		(drill 0.2032)
		(layers "F.Cu" "B.Cu")
		(net "GND")
	)
	(via
		(at 266.619482 -282.316682)
		(size 0.4572)
		(drill 0.2032)
		(layers "F.Cu" "B.Cu")
		(net "GND")
	)
	(via
		(at 315.250068 -426.69968)
		(size 0.4572)
		(drill 0.2032)
		(layers "F.Cu" "B.Cu")
		(net "GND")
	)
	(via
		(at 116.922042 -129.586482)
		(size 0.508)
		(drill 0.254)
		(layers "F.Cu" "B.Cu")
		(net "GND")
	)
	(via
		(at 264.729214 -201.56678)
		(size 0.4572)
		(drill 0.2032)
		(layers "F.Cu" "B.Cu")
		(net "GND")
	)
	(via
		(at 88.86317 -404.51786)
		(size 0.4572)
		(drill 0.254)
		(layers "F.Cu" "B.Cu")
		(net "GND")
	)
	(via
		(at 59.57697 -406.370536)
		(size 0.4572)
		(drill 0.254)
		(layers "F.Cu" "B.Cu")
		(net "GND")
	)
	(via
		(at 305.970432 -323.372226)
		(size 0.4572)
		(drill 0.2032)
		(layers "F.Cu" "B.Cu")
		(net "GND")
	)
	(via
		(at 342.664034 -222.761556)
		(size 0.4572)
		(drill 0.2032)
		(layers "F.Cu" "B.Cu")
		(net "GND")
	)
	(via
		(at 165.83533 -441.225432)
		(size 0.508)
		(drill 0.254)
		(layers "F.Cu" "B.Cu")
		(net "GND")
	)
	(via
		(at 345.123516 -262.872474)
		(size 0.4572)
		(drill 0.2032)
		(layers "F.Cu" "B.Cu")
		(net "GND")
	)
	(via
		(at 270.063214 -260.21665)
		(size 0.4572)
		(drill 0.2032)
		(layers "F.Cu" "B.Cu")
		(net "GND")
	)
	(via
		(at 435.823614 -217.716608)
		(size 0.4572)
		(drill 0.2032)
		(layers "F.Cu" "B.Cu")
		(net "GND")
	)
	(via
		(at 28.433014 -310.366664)
		(size 0.4572)
		(drill 0.2032)
		(layers "F.Cu" "B.Cu")
		(net "GND")
	)
	(via
		(at 447.467482 -238.116618)
		(size 0.4572)
		(drill 0.2032)
		(layers "F.Cu" "B.Cu")
		(net "GND")
	)
	(via
		(at 262.415782 -69.231256)
		(size 0.508)
		(drill 0.254)
		(layers "F.Cu" "B.Cu")
		(net "GND")
	)
	(via
		(at 300.34738 -411.204156)
		(size 0.508)
		(drill 0.254)
		(layers "F.Cu" "B.Cu")
		(net "GND")
	)
	(via
		(at 384.485134 -228.45903)
		(size 0.4318)
		(drill 0.2032)
		(layers "F.Cu" "B.Cu")
		(net "GND")
	)
	(via
		(at 101.27488 -80.935322)
		(size 0.508)
		(drill 0.254)
		(layers "F.Cu" "B.Cu")
		(net "GND")
	)
	(via
		(at 304.135282 -235.566712)
		(size 0.4572)
		(drill 0.2032)
		(layers "F.Cu" "B.Cu")
		(net "GND")
	)
	(via
		(at 136.066022 -335.957672)
		(size 0.508)
		(drill 0.254)
		(layers "F.Cu" "B.Cu")
		(net "GND")
	)
	(via
		(at 9.245346 -270.416782)
		(size 0.4572)
		(drill 0.2032)
		(layers "F.Cu" "B.Cu")
		(net "GND")
	)
	(via
		(at 259.05714 -422.9608)
		(size 0.508)
		(drill 0.254)
		(layers "F.Cu" "B.Cu")
		(net "GND")
	)
	(via
		(at 438.033414 -225.36658)
		(size 0.4572)
		(drill 0.2032)
		(layers "F.Cu" "B.Cu")
		(net "GND")
	)
	(via
		(at 27.547062 -10.16508)
		(size 0.508)
		(drill 0.254)
		(layers "F.Cu" "B.Cu")
		(net "GND")
	)
	(via
		(at 222.535496 -26.942288)
		(size 0.508)
		(drill 0.254)
		(layers "F.Cu" "B.Cu")
		(net "GND")
	)
	(via
		(at 335.138268 -55.498746)
		(size 0.4572)
		(drill 0.2032)
		(layers "F.Cu" "B.Cu")
		(net "GND")
	)
	(via
		(at 14.579346 -304.416714)
		(size 0.4572)
		(drill 0.2032)
		(layers "F.Cu" "B.Cu")
		(net "GND")
	)
	(via
		(at 351.558606 -292.955726)
		(size 0.508)
		(drill 0.254)
		(layers "F.Cu" "B.Cu")
		(net "GND")
	)
	(via
		(at 210.74888 -70.500748)
		(size 0.508)
		(drill 0.254)
		(layers "F.Cu" "B.Cu")
		(net "GND")
	)
	(via
		(at 16.789146 -240.666778)
		(size 0.4572)
		(drill 0.2032)
		(layers "F.Cu" "B.Cu")
		(net "GND")
	)
	(via
		(at 331.067918 -42.811446)
		(size 0.4572)
		(drill 0.2032)
		(layers "F.Cu" "B.Cu")
		(net "GND")
	)
	(via
		(at 33.767014 -215.166702)
		(size 0.4572)
		(drill 0.2032)
		(layers "F.Cu" "B.Cu")
		(net "GND")
	)
	(via
		(at 464.764882 -230.466646)
		(size 0.4572)
		(drill 0.2032)
		(layers "F.Cu" "B.Cu")
		(net "GND")
	)
	(via
		(at 323.250052 -438.651396)
		(size 0.4572)
		(drill 0.2032)
		(layers "F.Cu" "B.Cu")
		(net "GND")
	)
	(via
		(at 409.349956 -427.699678)
		(size 0.4572)
		(drill 0.2032)
		(layers "F.Cu" "B.Cu")
		(net "GND")
	)
	(via
		(at 11.135614 -207.51673)
		(size 0.4572)
		(drill 0.2032)
		(layers "F.Cu" "B.Cu")
		(net "GND")
	)
	(via
		(at 337.49488 -231.714548)
		(size 0.4572)
		(drill 0.2032)
		(layers "F.Cu" "B.Cu")
		(net "GND")
	)
	(via
		(at 377.076462 -287.28924)
		(size 0.4572)
		(drill 0.2032)
		(layers "F.Cu" "B.Cu")
		(net "GND")
	)
	(via
		(at 439.923682 -196.466714)
		(size 0.4572)
		(drill 0.2032)
		(layers "F.Cu" "B.Cu")
		(net "GND")
	)
	(via
		(at 200.265284 -323.434456)
		(size 0.4572)
		(drill 0.2032)
		(layers "F.Cu" "B.Cu")
		(net "GND")
	)
	(via
		(at 311.882282 -275.516594)
		(size 0.4572)
		(drill 0.2032)
		(layers "F.Cu" "B.Cu")
		(net "GND")
	)
	(via
		(at 18.88236 -168.509188)
		(size 0.508)
		(drill 0.254)
		(layers "F.Cu" "B.Cu")
		(net "GND")
	)
	(via
		(at 187.883546 -216.016586)
		(size 0.4572)
		(drill 0.2032)
		(layers "F.Cu" "B.Cu")
		(net "GND")
	)
	(via
		(at 298.44492 -148.750528)
		(size 0.508)
		(drill 0.254)
		(layers "F.Cu" "B.Cu")
		(net "GND")
	)
	(via
		(at 296.578782 -294.216582)
		(size 0.4572)
		(drill 0.2032)
		(layers "F.Cu" "B.Cu")
		(net "GND")
	)
	(via
		(at 205.180946 -276.366732)
		(size 0.4572)
		(drill 0.2032)
		(layers "F.Cu" "B.Cu")
		(net "GND")
	)
	(via
		(at 307.782214 -292.516814)
		(size 0.4572)
		(drill 0.2032)
		(layers "F.Cu" "B.Cu")
		(net "GND")
	)
	(via
		(at 447.467482 -235.566712)
		(size 0.4572)
		(drill 0.2032)
		(layers "F.Cu" "B.Cu")
		(net "GND")
	)
	(via
		(at 309.45074 -407.638504)
		(size 0.4572)
		(drill 0.254)
		(layers "F.Cu" "B.Cu")
		(net "GND")
	)
	(via
		(at 411.973522 -215.166702)
		(size 0.4572)
		(drill 0.2032)
		(layers "F.Cu" "B.Cu")
		(net "GND")
	)
	(via
		(at 309.992014 -296.766742)
		(size 0.4572)
		(drill 0.2032)
		(layers "F.Cu" "B.Cu")
		(net "GND")
	)
	(via
		(at 92.484194 -284.033722)
		(size 0.4572)
		(drill 0.2032)
		(layers "F.Cu" "B.Cu")
		(net "GND")
	)
	(via
		(at 63.942214 -299.316648)
		(size 0.4572)
		(drill 0.2032)
		(layers "F.Cu" "B.Cu")
		(net "GND")
	)
	(via
		(at 203.107798 -193.96075)
		(size 0.508)
		(drill 0.254)
		(layers "F.Cu" "B.Cu")
		(net "GND")
	)
	(via
		(at 22.123146 -240.666778)
		(size 0.4572)
		(drill 0.2032)
		(layers "F.Cu" "B.Cu")
		(net "GND")
	)
	(via
		(at 103.761794 -275.8948)
		(size 0.4572)
		(drill 0.2032)
		(layers "F.Cu" "B.Cu")
		(net "GND")
	)
	(via
		(at 210.514946 -268.71676)
		(size 0.4572)
		(drill 0.2032)
		(layers "F.Cu" "B.Cu")
		(net "GND")
	)
	(via
		(at 77.166978 -340.92515)
		(size 0.508)
		(drill 0.254)
		(layers "F.Cu" "B.Cu")
		(net "GND")
	)
	(via
		(at 339.374734 -220.319854)
		(size 0.4572)
		(drill 0.2032)
		(layers "F.Cu" "B.Cu")
		(net "GND")
	)
	(via
		(at 450.911214 -236.416596)
		(size 0.4572)
		(drill 0.2032)
		(layers "F.Cu" "B.Cu")
		(net "GND")
	)
	(via
		(at 153.359866 -123.678188)
		(size 0.508)
		(drill 0.254)
		(layers "F.Cu" "B.Cu")
		(net "GND")
	)
	(via
		(at 157.609794 -295.06672)
		(size 0.4572)
		(drill 0.2032)
		(layers "F.Cu" "B.Cu")
		(net "GND")
	)
	(via
		(at 382.35001 -427.851316)
		(size 0.4572)
		(drill 0.2032)
		(layers "F.Cu" "B.Cu")
		(net "GND")
	)
	(via
		(at 362.509562 -278.336248)
		(size 0.4572)
		(drill 0.2032)
		(layers "F.Cu" "B.Cu")
		(net "GND")
	)
	(via
		(at 292.694614 -227.066602)
		(size 0.4572)
		(drill 0.2032)
		(layers "F.Cu" "B.Cu")
		(net "GND")
	)
	(via
		(at 38.221158 -6.597396)
		(size 0.508)
		(drill 0.254)
		(layers "F.Cu" "B.Cu")
		(net "GND")
	)
	(via
		(at 120.208548 -275.08073)
		(size 0.4572)
		(drill 0.2032)
		(layers "F.Cu" "B.Cu")
		(net "GND")
	)
	(via
		(at 323.781928 -400.858228)
		(size 0.4064)
		(drill 0.2032)
		(layers "F.Cu" "B.Cu")
		(net "GND")
	)
	(via
		(at 306.548282 -303.566576)
		(size 0.4572)
		(drill 0.2032)
		(layers "F.Cu" "B.Cu")
		(net "GND")
	)
	(via
		(at 209.281014 -207.51673)
		(size 0.4572)
		(drill 0.2032)
		(layers "F.Cu" "B.Cu")
		(net "GND")
	)
	(via
		(at 332.435962 -260.430772)
		(size 0.4572)
		(drill 0.2032)
		(layers "F.Cu" "B.Cu")
		(net "GND")
	)
	(via
		(at 412.956756 -7.215124)
		(size 0.508)
		(drill 0.254)
		(layers "F.Cu" "B.Cu")
		(net "GND")
	)
	(via
		(at 52.298346 -248.31675)
		(size 0.4572)
		(drill 0.2032)
		(layers "F.Cu" "B.Cu")
		(net "GND")
	)
	(via
		(at 396.690596 -16.967454)
		(size 0.508)
		(drill 0.254)
		(layers "F.Cu" "B.Cu")
		(net "GND")
	)
	(via
		(at 430.489614 -315.46673)
		(size 0.4572)
		(drill 0.2032)
		(layers "F.Cu" "B.Cu")
		(net "GND")
	)
	(via
		(at 94.723966 -219.506038)
		(size 0.4572)
		(drill 0.2032)
		(layers "F.Cu" "B.Cu")
		(net "GND")
	)
	(via
		(at 156.31668 -10.754868)
		(size 0.508)
		(drill 0.254)
		(layers "F.Cu" "B.Cu")
		(net "GND")
	)
	(via
		(at 407.858214 -263.616694)
		(size 0.4572)
		(drill 0.2032)
		(layers "F.Cu" "B.Cu")
		(net "GND")
	)
	(via
		(at 134.195566 -226.017328)
		(size 0.4572)
		(drill 0.2032)
		(layers "F.Cu" "B.Cu")
		(net "GND")
	)
	(via
		(at 434.589682 -282.316682)
		(size 0.4572)
		(drill 0.2032)
		(layers "F.Cu" "B.Cu")
		(net "GND")
	)
	(via
		(at 340.784434 -227.64496)
		(size 0.4572)
		(drill 0.2032)
		(layers "F.Cu" "B.Cu")
		(net "GND")
	)
	(via
		(at 277.607014 -195.616576)
		(size 0.4572)
		(drill 0.2032)
		(layers "F.Cu" "B.Cu")
		(net "GND")
	)
	(via
		(at 123.662694 -78.587092)
		(size 0.508)
		(drill 0.254)
		(layers "F.Cu" "B.Cu")
		(net "GND")
	)
	(via
		(at 447.467482 -202.416664)
		(size 0.4572)
		(drill 0.2032)
		(layers "F.Cu" "B.Cu")
		(net "GND")
	)
	(via
		(at 39.263574 -386.329174)
		(size 0.508)
		(drill 0.254)
		(layers "F.Cu" "B.Cu")
		(net "GND")
	)
	(via
		(at 305.402488 -400.858228)
		(size 0.4064)
		(drill 0.2032)
		(layers "F.Cu" "B.Cu")
		(net "GND")
	)
	(via
		(at 276.373082 -211.766658)
		(size 0.4572)
		(drill 0.2032)
		(layers "F.Cu" "B.Cu")
		(net "GND")
	)
	(via
		(at 455.011282 -215.166702)
		(size 0.4572)
		(drill 0.2032)
		(layers "F.Cu" "B.Cu")
		(net "GND")
	)
	(via
		(at 383.655062 -271.011396)
		(size 0.4572)
		(drill 0.2032)
		(layers "F.Cu" "B.Cu")
		(net "GND")
	)
	(via
		(at 464.53552 -413.15513)
		(size 0.508)
		(drill 0.254)
		(layers "F.Cu" "B.Cu")
		(net "GND")
	)
	(via
		(at 292.694614 -238.966756)
		(size 0.4572)
		(drill 0.2032)
		(layers "F.Cu" "B.Cu")
		(net "GND")
	)
	(via
		(at 172.795946 -225.36658)
		(size 0.4572)
		(drill 0.2032)
		(layers "F.Cu" "B.Cu")
		(net "GND")
	)
	(via
		(at 2.764536 -249.350022)
		(size 0.508)
		(drill 0.254)
		(layers "F.Cu" "B.Cu")
		(net "GND")
	)
	(via
		(at 212.724746 -201.56678)
		(size 0.4572)
		(drill 0.2032)
		(layers "F.Cu" "B.Cu")
		(net "GND")
	)
	(via
		(at 58.824114 -288.266632)
		(size 0.4572)
		(drill 0.2032)
		(layers "F.Cu" "B.Cu")
		(net "GND")
	)
	(via
		(at 354.881434 -222.761556)
		(size 0.4572)
		(drill 0.2032)
		(layers "F.Cu" "B.Cu")
		(net "GND")
	)
	(via
		(at 253.393448 -99.518216)
		(size 0.508)
		(drill 0.254)
		(layers "F.Cu" "B.Cu")
		(net "GND")
	)
	(via
		(at 439.923682 -249.166634)
		(size 0.4572)
		(drill 0.2032)
		(layers "F.Cu" "B.Cu")
		(net "GND")
	)
	(via
		(at 56.83885 -148.470874)
		(size 0.49022)
		(drill 0.254)
		(layers "F.Cu" "B.Cu")
		(net "GND")
	)
	(via
		(at 418.883846 -154.183588)
		(size 0.49022)
		(drill 0.254)
		(layers "F.Cu" "B.Cu")
		(net "GND")
	)
	(via
		(at 180.339746 -214.316564)
		(size 0.4572)
		(drill 0.2032)
		(layers "F.Cu" "B.Cu")
		(net "GND")
	)
	(via
		(at 378.016262 -262.872474)
		(size 0.4572)
		(drill 0.2032)
		(layers "F.Cu" "B.Cu")
		(net "GND")
	)
	(via
		(at 9.245346 -298.466764)
		(size 0.4572)
		(drill 0.2032)
		(layers "F.Cu" "B.Cu")
		(net "GND")
	)
	(via
		(at 51.064414 -297.616626)
		(size 0.4572)
		(drill 0.2032)
		(layers "F.Cu" "B.Cu")
		(net "GND")
	)
	(via
		(at 274.163282 -297.616626)
		(size 0.4572)
		(drill 0.2032)
		(layers "F.Cu" "B.Cu")
		(net "GND")
	)
	(via
		(at 157.08884 -30.312868)
		(size 0.508)
		(drill 0.254)
		(layers "F.Cu" "B.Cu")
		(net "GND")
	)
	(via
		(at 266.619482 -294.216582)
		(size 0.4572)
		(drill 0.2032)
		(layers "F.Cu" "B.Cu")
		(net "GND")
	)
	(via
		(at 278.839676 -17.241774)
		(size 0.508)
		(drill 0.254)
		(layers "F.Cu" "B.Cu")
		(net "GND")
	)
	(via
		(at 39.420546 -236.416596)
		(size 0.4572)
		(drill 0.2032)
		(layers "F.Cu" "B.Cu")
		(net "GND")
	)
	(via
		(at 169.927016 -10.591292)
		(size 0.508)
		(drill 0.254)
		(layers "F.Cu" "B.Cu")
		(net "GND")
	)
	(via
		(at 46.964346 -223.666558)
		(size 0.4572)
		(drill 0.2032)
		(layers "F.Cu" "B.Cu")
		(net "GND")
	)
	(via
		(at 331.065378 -51.269646)
		(size 0.4572)
		(drill 0.2032)
		(layers "F.Cu" "B.Cu")
		(net "GND")
	)
	(via
		(at 107.685332 -406.477724)
		(size 0.508)
		(drill 0.254)
		(layers "F.Cu" "B.Cu")
		(net "GND")
	)
	(via
		(at 369.271042 -52.319428)
		(size 0.508)
		(drill 0.254)
		(layers "F.Cu" "B.Cu")
		(net "GND")
	)
	(via
		(at 70.48373 -404.51786)
		(size 0.4572)
		(drill 0.254)
		(layers "F.Cu" "B.Cu")
		(net "GND")
	)
	(via
		(at 318.252094 -28.423362)
		(size 0.508)
		(drill 0.254)
		(layers "F.Cu" "B.Cu")
		(net "GND")
	)
	(via
		(at 417.292282 -233.86669)
		(size 0.4572)
		(drill 0.2032)
		(layers "F.Cu" "B.Cu")
		(net "GND")
	)
	(via
		(at 360.520234 -219.506038)
		(size 0.4572)
		(drill 0.2032)
		(layers "F.Cu" "B.Cu")
		(net "GND")
	)
	(via
		(at 281.707082 -289.966654)
		(size 0.4572)
		(drill 0.2032)
		(layers "F.Cu" "B.Cu")
		(net "GND")
	)
	(via
		(at 272.273014 -278.066754)
		(size 0.4572)
		(drill 0.2032)
		(layers "F.Cu" "B.Cu")
		(net "GND")
	)
	(via
		(at 343.0397 -25.814528)
		(size 0.508)
		(drill 0.254)
		(layers "F.Cu" "B.Cu")
		(net "GND")
	)
	(via
		(at 92.844366 -235.783882)
		(size 0.4572)
		(drill 0.2032)
		(layers "F.Cu" "B.Cu")
		(net "GND")
	)
	(via
		(at 462.555082 -202.416664)
		(size 0.4572)
		(drill 0.2032)
		(layers "F.Cu" "B.Cu")
		(net "GND")
	)
	(via
		(at 153.34996 -428.851314)
		(size 0.4572)
		(drill 0.2032)
		(layers "F.Cu" "B.Cu")
		(net "GND")
	)
	(via
		(at 373.207534 -239.853216)
		(size 0.4572)
		(drill 0.2032)
		(layers "F.Cu" "B.Cu")
		(net "GND")
	)
	(via
		(at 348.772734 -231.714548)
		(size 0.4572)
		(drill 0.2032)
		(layers "F.Cu" "B.Cu")
		(net "GND")
	)
	(via
		(at 346.20962 -407.638504)
		(size 0.4572)
		(drill 0.254)
		(layers "F.Cu" "B.Cu")
		(net "GND")
	)
	(via
		(at 338.544916 -277.522432)
		(size 0.4572)
		(drill 0.2032)
		(layers "F.Cu" "B.Cu")
		(net "GND")
	)
	(via
		(at 337.604862 -275.8948)
		(size 0.4572)
		(drill 0.2032)
		(layers "F.Cu" "B.Cu")
		(net "GND")
	)
	(via
		(at 11.135614 -210.066636)
		(size 0.4572)
		(drill 0.2032)
		(layers "F.Cu" "B.Cu")
		(net "GND")
	)
	(via
		(at 434.589682 -238.116618)
		(size 0.4572)
		(drill 0.2032)
		(layers "F.Cu" "B.Cu")
		(net "GND")
	)
	(via
		(at 430.489614 -261.916672)
		(size 0.4572)
		(drill 0.2032)
		(layers "F.Cu" "B.Cu")
		(net "GND")
	)
	(via
		(at 274.163282 -282.316682)
		(size 0.4572)
		(drill 0.2032)
		(layers "F.Cu" "B.Cu")
		(net "GND")
	)
	(via
		(at 276.373082 -238.116618)
		(size 0.4572)
		(drill 0.2032)
		(layers "F.Cu" "B.Cu")
		(net "GND")
	)
	(via
		(at 44.754546 -201.56678)
		(size 0.4572)
		(drill 0.2032)
		(layers "F.Cu" "B.Cu")
		(net "GND")
	)
	(via
		(at 265.424412 -67.88785)
		(size 0.6604)
		(drill 0.3302)
		(layers "F.Cu" "B.Cu")
		(net "GND")
	)
	(via
		(at 182.549546 -238.966756)
		(size 0.4572)
		(drill 0.2032)
		(layers "F.Cu" "B.Cu")
		(net "GND")
	)
	(via
		(at 33.767014 -258.516628)
		(size 0.4572)
		(drill 0.2032)
		(layers "F.Cu" "B.Cu")
		(net "GND")
	)
	(via
		(at 405.648414 -214.316564)
		(size 0.4572)
		(drill 0.2032)
		(layers "F.Cu" "B.Cu")
		(net "GND")
	)
	(via
		(at 13.345414 -213.46668)
		(size 0.4572)
		(drill 0.2032)
		(layers "F.Cu" "B.Cu")
		(net "GND")
	)
	(via
		(at 304.338482 -301.01667)
		(size 0.4572)
		(drill 0.2032)
		(layers "F.Cu" "B.Cu")
		(net "GND")
	)
	(via
		(at 58.608214 -216.866724)
		(size 0.4572)
		(drill 0.2032)
		(layers "F.Cu" "B.Cu")
		(net "GND")
	)
	(via
		(at 2.764536 -239.190022)
		(size 0.508)
		(drill 0.254)
		(layers "F.Cu" "B.Cu")
		(net "GND")
	)
	(via
		(at 54.724046 -292.516814)
		(size 0.4572)
		(drill 0.2032)
		(layers "F.Cu" "B.Cu")
		(net "GND")
	)
	(via
		(at 86.084918 -342.769952)
		(size 0.508)
		(drill 0.254)
		(layers "F.Cu" "B.Cu")
		(net "GND")
	)
	(via
		(at 115.426236 -259.635244)
		(size 0.4572)
		(drill 0.2032)
		(layers "F.Cu" "B.Cu")
		(net "GND")
	)
	(via
		(at 398.794478 -403.249892)
		(size 0.4572)
		(drill 0.254)
		(layers "F.Cu" "B.Cu")
		(net "GND")
	)
	(via
		(at 117.279166 -234.15625)
		(size 0.4572)
		(drill 0.2032)
		(layers "F.Cu" "B.Cu")
		(net "GND")
	)
	(via
		(at 195.427346 -306.116736)
		(size 0.4572)
		(drill 0.2032)
		(layers "F.Cu" "B.Cu")
		(net "GND")
	)
	(via
		(at 76.250038 -425.547282)
		(size 0.4572)
		(drill 0.2032)
		(layers "F.Cu" "B.Cu")
		(net "GND")
	)
	(via
		(at 58.318146 -407.638504)
		(size 0.4572)
		(drill 0.254)
		(layers "F.Cu" "B.Cu")
		(net "GND")
	)
	(via
		(at 394.349986 -432.747166)
		(size 0.4572)
		(drill 0.2032)
		(layers "F.Cu" "B.Cu")
		(net "GND")
	)
	(via
		(at 387.625082 -37.14115)
		(size 0.508)
		(drill 0.254)
		(layers "F.Cu" "B.Cu")
		(net "GND")
	)
	(via
		(at 119.158766 -227.64496)
		(size 0.4572)
		(drill 0.2032)
		(layers "F.Cu" "B.Cu")
		(net "GND")
	)
	(via
		(at 407.858214 -234.716574)
		(size 0.4572)
		(drill 0.2032)
		(layers "F.Cu" "B.Cu")
		(net "GND")
	)
	(via
		(at 55.817008 -355.244146)
		(size 0.508)
		(drill 0.254)
		(layers "F.Cu" "B.Cu")
		(net "GND")
	)
	(via
		(at 129.496566 -216.25052)
		(size 0.4572)
		(drill 0.2032)
		(layers "F.Cu" "B.Cu")
		(net "GND")
	)
	(via
		(at 306.548282 -299.316648)
		(size 0.4572)
		(drill 0.2032)
		(layers "F.Cu" "B.Cu")
		(net "GND")
	)
	(via
		(at 181.68112 -351.614994)
		(size 0.49022)
		(drill 0.254)
		(layers "F.Cu" "B.Cu")
		(net "GND")
	)
	(via
		(at 90.872056 -79.815436)
		(size 0.508)
		(drill 0.254)
		(layers "F.Cu" "B.Cu")
		(net "GND")
	)
	(via
		(at 257.185414 -273.816572)
		(size 0.4572)
		(drill 0.2032)
		(layers "F.Cu" "B.Cu")
		(net "GND")
	)
	(via
		(at 419.502082 -221.116652)
		(size 0.4572)
		(drill 0.2032)
		(layers "F.Cu" "B.Cu")
		(net "GND")
	)
	(via
		(at 304.338482 -200.716642)
		(size 0.4572)
		(drill 0.2032)
		(layers "F.Cu" "B.Cu")
		(net "GND")
	)
	(via
		(at 100.942648 -279.150318)
		(size 0.4572)
		(drill 0.2032)
		(layers "F.Cu" "B.Cu")
		(net "GND")
	)
	(via
		(at 113.519966 -232.528364)
		(size 0.4572)
		(drill 0.2032)
		(layers "F.Cu" "B.Cu")
		(net "GND")
	)
	(via
		(at 384.824478 -407.638504)
		(size 0.4572)
		(drill 0.254)
		(layers "F.Cu" "B.Cu")
		(net "GND")
	)
	(via
		(at 328.191368 -410.030168)
		(size 0.4064)
		(drill 0.2032)
		(layers "F.Cu" "B.Cu")
		(net "GND")
	)
	(via
		(at 210.514946 -279.766776)
		(size 0.4572)
		(drill 0.2032)
		(layers "F.Cu" "B.Cu")
		(net "GND")
	)
	(via
		(at 84.856066 -223.575626)
		(size 0.4572)
		(drill 0.2032)
		(layers "F.Cu" "B.Cu")
		(net "GND")
	)
	(via
		(at 35.976814 -310.366664)
		(size 0.4572)
		(drill 0.2032)
		(layers "F.Cu" "B.Cu")
		(net "GND")
	)
	(via
		(at 181.31028 -124.145548)
		(size 0.508)
		(drill 0.254)
		(layers "F.Cu" "B.Cu")
		(net "GND")
	)
	(via
		(at 214.615014 -262.76681)
		(size 0.4572)
		(drill 0.2032)
		(layers "F.Cu" "B.Cu")
		(net "GND")
	)
	(via
		(at 365.798862 -275.8948)
		(size 0.4572)
		(drill 0.2032)
		(layers "F.Cu" "B.Cu")
		(net "GND")
	)
	(via
		(at 343.603834 -222.761556)
		(size 0.4572)
		(drill 0.2032)
		(layers "F.Cu" "B.Cu")
		(net "GND")
	)
	(via
		(at 44.754546 -276.366732)
		(size 0.4572)
		(drill 0.2032)
		(layers "F.Cu" "B.Cu")
		(net "GND")
	)
	(via
		(at 107.881166 -216.25052)
		(size 0.4572)
		(drill 0.2032)
		(layers "F.Cu" "B.Cu")
		(net "GND")
	)
	(via
		(at 306.548282 -262.76681)
		(size 0.4572)
		(drill 0.2032)
		(layers "F.Cu" "B.Cu")
		(net "GND")
	)
	(via
		(at 353.941634 -229.272846)
		(size 0.4572)
		(drill 0.2032)
		(layers "F.Cu" "B.Cu")
		(net "GND")
	)
	(via
		(at 460.664814 -290.816792)
		(size 0.4572)
		(drill 0.2032)
		(layers "F.Cu" "B.Cu")
		(net "GND")
	)
	(via
		(at 147.068286 -406.370536)
		(size 0.4572)
		(drill 0.254)
		(layers "F.Cu" "B.Cu")
		(net "GND")
	)
	(via
		(at 326.799194 -66.270632)
		(size 0.508)
		(drill 0.254)
		(layers "F.Cu" "B.Cu")
		(net "GND")
	)
	(via
		(at 314.092082 -305.266598)
		(size 0.4572)
		(drill 0.2032)
		(layers "F.Cu" "B.Cu")
		(net "GND")
	)
	(via
		(at 460.664814 -212.616796)
		(size 0.4572)
		(drill 0.2032)
		(layers "F.Cu" "B.Cu")
		(net "GND")
	)
	(via
		(at 9.245346 -307.816758)
		(size 0.4572)
		(drill 0.2032)
		(layers "F.Cu" "B.Cu")
		(net "GND")
	)
	(via
		(at 180.955696 -114.975386)
		(size 0.4572)
		(drill 0.254)
		(layers "F.Cu" "B.Cu")
		(net "GND")
	)
	(via
		(at 37.210746 -217.716608)
		(size 0.4572)
		(drill 0.2032)
		(layers "F.Cu" "B.Cu")
		(net "GND")
	)
	(via
		(at 287.433766 -361.625388)
		(size 0.49022)
		(drill 0.254)
		(layers "F.Cu" "B.Cu")
		(net "GND")
	)
	(via
		(at 435.823614 -306.116736)
		(size 0.4572)
		(drill 0.2032)
		(layers "F.Cu" "B.Cu")
		(net "GND")
	)
	(via
		(at 54.508146 -214.316564)
		(size 0.4572)
		(drill 0.2032)
		(layers "F.Cu" "B.Cu")
		(net "GND")
	)
	(via
		(at 274.163282 -196.466714)
		(size 0.4572)
		(drill 0.2032)
		(layers "F.Cu" "B.Cu")
		(net "GND")
	)
	(via
		(at 131.015994 -287.28924)
		(size 0.4572)
		(drill 0.2032)
		(layers "F.Cu" "B.Cu")
		(net "GND")
	)
	(via
		(at 169.352214 -278.916638)
		(size 0.4572)
		(drill 0.2032)
		(layers "F.Cu" "B.Cu")
		(net "GND")
	)
	(via
		(at 59.842146 -260.21665)
		(size 0.4572)
		(drill 0.2032)
		(layers "F.Cu" "B.Cu")
		(net "GND")
	)
	(via
		(at 58.608214 -282.316682)
		(size 0.4572)
		(drill 0.2032)
		(layers "F.Cu" "B.Cu")
		(net "GND")
	)
	(via
		(at 128.556766 -226.017328)
		(size 0.4572)
		(drill 0.2032)
		(layers "F.Cu" "B.Cu")
		(net "GND")
	)
	(via
		(at 43.520614 -295.916604)
		(size 0.4572)
		(drill 0.2032)
		(layers "F.Cu" "B.Cu")
		(net "GND")
	)
	(via
		(at 431.110136 -5.585714)
		(size 0.508)
		(drill 0.254)
		(layers "F.Cu" "B.Cu")
		(net "GND")
	)
	(via
		(at 415.402014 -250.016772)
		(size 0.4572)
		(drill 0.2032)
		(layers "F.Cu" "B.Cu")
		(net "GND")
	)
	(via
		(at 18.679414 -310.366664)
		(size 0.4572)
		(drill 0.2032)
		(layers "F.Cu" "B.Cu")
		(net "GND")
	)
	(via
		(at 367.568734 -226.831144)
		(size 0.4572)
		(drill 0.2032)
		(layers "F.Cu" "B.Cu")
		(net "GND")
	)
	(via
		(at 257.185414 -261.916672)
		(size 0.4572)
		(drill 0.2032)
		(layers "F.Cu" "B.Cu")
		(net "GND")
	)
	(via
		(at 344.653616 -281.59202)
		(size 0.4572)
		(drill 0.2032)
		(layers "F.Cu" "B.Cu")
		(net "GND")
	)
	(via
		(at 413.50438 -159.095948)
		(size 0.508)
		(drill 0.254)
		(layers "F.Cu" "B.Cu")
		(net "GND")
	)
	(via
		(at 301.45482 -417.990528)
		(size 0.508)
		(drill 0.254)
		(layers "F.Cu" "B.Cu")
		(net "GND")
	)
	(via
		(at 67.781678 -403.883876)
		(size 0.4064)
		(drill 0.2032)
		(layers "F.Cu" "B.Cu")
		(net "GND")
	)
	(via
		(at 464.764882 -278.916638)
		(size 0.4572)
		(drill 0.2032)
		(layers "F.Cu" "B.Cu")
		(net "GND")
	)
	(via
		(at 336.250026 -429.147224)
		(size 0.4572)
		(drill 0.2032)
		(layers "F.Cu" "B.Cu")
		(net "GND")
	)
	(via
		(at 167.461946 -296.766742)
		(size 0.4572)
		(drill 0.2032)
		(layers "F.Cu" "B.Cu")
		(net "GND")
	)
	(via
		(at 167.65778 -311.216802)
		(size 0.4572)
		(drill 0.2032)
		(layers "F.Cu" "B.Cu")
		(net "GND")
	)
	(via
		(at 93.90126 -109.680248)
		(size 0.508)
		(drill 0.254)
		(layers "F.Cu" "B.Cu")
		(net "GND")
	)
	(via
		(at 371.907562 -279.964134)
		(size 0.4572)
		(drill 0.2032)
		(layers "F.Cu" "B.Cu")
		(net "GND")
	)
	(via
		(at 132.895848 -264.50036)
		(size 0.4572)
		(drill 0.2032)
		(layers "F.Cu" "B.Cu")
		(net "GND")
	)
	(via
		(at 118.328948 -270.19758)
		(size 0.4572)
		(drill 0.2032)
		(layers "F.Cu" "B.Cu")
		(net "GND")
	)
	(via
		(at 191.983614 -316.316614)
		(size 0.4572)
		(drill 0.2032)
		(layers "F.Cu" "B.Cu")
		(net "GND")
	)
	(via
		(at 264.729214 -238.966756)
		(size 0.4572)
		(drill 0.2032)
		(layers "F.Cu" "B.Cu")
		(net "GND")
	)
	(via
		(at 197.637146 -287.416748)
		(size 0.4572)
		(drill 0.2032)
		(layers "F.Cu" "B.Cu")
		(net "GND")
	)
	(via
		(at 279.816814 -307.816758)
		(size 0.4572)
		(drill 0.2032)
		(layers "F.Cu" "B.Cu")
		(net "GND")
	)
	(via
		(at 439.923682 -244.066568)
		(size 0.4572)
		(drill 0.2032)
		(layers "F.Cu" "B.Cu")
		(net "GND")
	)
	(via
		(at 254.975614 -311.216802)
		(size 0.4572)
		(drill 0.2032)
		(layers "F.Cu" "B.Cu")
		(net "GND")
	)
	(via
		(at 303.421288 -403.883876)
		(size 0.4064)
		(drill 0.2032)
		(layers "F.Cu" "B.Cu")
		(net "GND")
	)
	(via
		(at 447.467482 -288.266632)
		(size 0.4572)
		(drill 0.2032)
		(layers "F.Cu" "B.Cu")
		(net "GND")
	)
	(via
		(at 136.184894 -262.058658)
		(size 0.4572)
		(drill 0.2032)
		(layers "F.Cu" "B.Cu")
		(net "GND")
	)
	(via
		(at 345.123262 -277.522432)
		(size 0.4572)
		(drill 0.2032)
		(layers "F.Cu" "B.Cu")
		(net "GND")
	)
	(via
		(at 443.367414 -278.066754)
		(size 0.4572)
		(drill 0.2032)
		(layers "F.Cu" "B.Cu")
		(net "GND")
	)
	(via
		(at 384.015234 -245.55069)
		(size 0.4572)
		(drill 0.2032)
		(layers "F.Cu" "B.Cu")
		(net "GND")
	)
	(via
		(at 120.0912 -76.063348)
		(size 0.508)
		(drill 0.254)
		(layers "F.Cu" "B.Cu")
		(net "GND")
	)
	(via
		(at 69.250052 -428.851314)
		(size 0.4572)
		(drill 0.2032)
		(layers "F.Cu" "B.Cu")
		(net "GND")
	)
	(via
		(at 42.057066 -7.215124)
		(size 0.508)
		(drill 0.254)
		(layers "F.Cu" "B.Cu")
		(net "GND")
	)
	(via
		(at 432.379882 -204.116686)
		(size 0.4572)
		(drill 0.2032)
		(layers "F.Cu" "B.Cu")
		(net "GND")
	)
	(via
		(at 214.615014 -238.116618)
		(size 0.4572)
		(drill 0.2032)
		(layers "F.Cu" "B.Cu")
		(net "GND")
	)
	(via
		(at 266.619482 -297.616626)
		(size 0.4572)
		(drill 0.2032)
		(layers "F.Cu" "B.Cu")
		(net "GND")
	)
	(via
		(at 216.824814 -244.066568)
		(size 0.4572)
		(drill 0.2032)
		(layers "F.Cu" "B.Cu")
		(net "GND")
	)
	(via
		(at 170.5229 -355.538278)
		(size 0.49022)
		(drill 0.254)
		(layers "F.Cu" "B.Cu")
		(net "GND")
	)
	(via
		(at 351.077276 -407.638504)
		(size 0.4572)
		(drill 0.254)
		(layers "F.Cu" "B.Cu")
		(net "GND")
	)
	(via
		(at 153.9748 -130.774948)
		(size 0.508)
		(drill 0.254)
		(layers "F.Cu" "B.Cu")
		(net "GND")
	)
	(via
		(at 218.372436 -94.750128)
		(size 0.508)
		(drill 0.254)
		(layers "F.Cu" "B.Cu")
		(net "GND")
	)
	(via
		(at 76.105512 -40.310562)
		(size 0.508)
		(drill 0.254)
		(layers "F.Cu" "B.Cu")
		(net "GND")
	)
	(via
		(at 74.990198 -403.883876)
		(size 0.4064)
		(drill 0.2032)
		(layers "F.Cu" "B.Cu")
		(net "GND")
	)
	(via
		(at 336.085434 -248.806208)
		(size 0.4572)
		(drill 0.2032)
		(layers "F.Cu" "B.Cu")
		(net "GND")
	)
	(via
		(at 281.707082 -196.466714)
		(size 0.4572)
		(drill 0.2032)
		(layers "F.Cu" "B.Cu")
		(net "GND")
	)
	(via
		(at 59.250072 -438.651396)
		(size 0.4572)
		(drill 0.2032)
		(layers "F.Cu" "B.Cu")
		(net "GND")
	)
	(via
		(at 172.795946 -248.31675)
		(size 0.4572)
		(drill 0.2032)
		(layers "F.Cu" "B.Cu")
		(net "GND")
	)
	(via
		(at 46.964346 -287.416748)
		(size 0.4572)
		(drill 0.2032)
		(layers "F.Cu" "B.Cu")
		(net "GND")
	)
	(via
		(at 412.232094 -216.866724)
		(size 0.4572)
		(drill 0.2032)
		(layers "F.Cu" "B.Cu")
		(net "GND")
	)
	(via
		(at 453.121014 -204.96657)
		(size 0.4572)
		(drill 0.2032)
		(layers "F.Cu" "B.Cu")
		(net "GND")
	)
	(via
		(at 339.484716 -287.28924)
		(size 0.4572)
		(drill 0.2032)
		(layers "F.Cu" "B.Cu")
		(net "GND")
	)
	(via
		(at 174.213774 -351.619058)
		(size 0.49022)
		(drill 0.254)
		(layers "F.Cu" "B.Cu")
		(net "GND")
	)
	(via
		(at 108.930694 -278.336502)
		(size 0.4572)
		(drill 0.2032)
		(layers "F.Cu" "B.Cu")
		(net "GND")
	)
	(via
		(at 56.971946 -401.492212)
		(size 0.4572)
		(drill 0.254)
		(layers "F.Cu" "B.Cu")
		(net "GND")
	)
	(via
		(at 44.754546 -307.816758)
		(size 0.4572)
		(drill 0.2032)
		(layers "F.Cu" "B.Cu")
		(net "GND")
	)
	(via
		(at 259.075682 -295.916604)
		(size 0.4572)
		(drill 0.2032)
		(layers "F.Cu" "B.Cu")
		(net "GND")
	)
	(via
		(at 359.906316 -331.776832)
		(size 0.49022)
		(drill 0.254)
		(layers "F.Cu" "B.Cu")
		(net "GND")
	)
	(via
		(at 121.038366 -222.761556)
		(size 0.4572)
		(drill 0.2032)
		(layers "F.Cu" "B.Cu")
		(net "GND")
	)
	(via
		(at 20.346924 -7.215124)
		(size 0.508)
		(drill 0.254)
		(layers "F.Cu" "B.Cu")
		(net "GND")
	)
	(via
		(at 89.466166 -335.187036)
		(size 0.49022)
		(drill 0.254)
		(layers "F.Cu" "B.Cu")
		(net "GND")
	)
	(via
		(at 57.572656 -152.936702)
		(size 0.508)
		(drill 0.254)
		(layers "F.Cu" "B.Cu")
		(net "GND")
	)
	(via
		(at 407.91765 -295.041574)
		(size 0.4572)
		(drill 0.2032)
		(layers "F.Cu" "B.Cu")
		(net "GND")
	)
	(via
		(at 103.182166 -216.25052)
		(size 0.4572)
		(drill 0.2032)
		(layers "F.Cu" "B.Cu")
		(net "GND")
	)
	(via
		(at 90.20937 -407.638504)
		(size 0.4572)
		(drill 0.254)
		(layers "F.Cu" "B.Cu")
		(net "GND")
	)
	(via
		(at 404.333964 -441.225432)
		(size 0.508)
		(drill 0.254)
		(layers "F.Cu" "B.Cu")
		(net "GND")
	)
	(via
		(at 129.136648 -256.361438)
		(size 0.4572)
		(drill 0.2032)
		(layers "F.Cu" "B.Cu")
		(net "GND")
	)
	(via
		(at 276.373082 -194.766692)
		(size 0.4572)
		(drill 0.2032)
		(layers "F.Cu" "B.Cu")
		(net "GND")
	)
	(via
		(at 425.444412 -17.601438)
		(size 0.508)
		(drill 0.254)
		(layers "F.Cu" "B.Cu")
		(net "GND")
	)
	(via
		(at 458.455014 -199.01662)
		(size 0.4572)
		(drill 0.2032)
		(layers "F.Cu" "B.Cu")
		(net "GND")
	)
	(via
		(at 304.338482 -244.066568)
		(size 0.4572)
		(drill 0.2032)
		(layers "F.Cu" "B.Cu")
		(net "GND")
	)
	(via
		(at 31.876746 -246.616728)
		(size 0.4572)
		(drill 0.2032)
		(layers "F.Cu" "B.Cu")
		(net "GND")
	)
	(via
		(at 453.121014 -199.01662)
		(size 0.4572)
		(drill 0.2032)
		(layers "F.Cu" "B.Cu")
		(net "GND")
	)
	(via
		(at 413.192214 -295.06672)
		(size 0.4572)
		(drill 0.2032)
		(layers "F.Cu" "B.Cu")
		(net "GND")
	)
	(via
		(at 347.363034 -245.55069)
		(size 0.4572)
		(drill 0.2032)
		(layers "F.Cu" "B.Cu")
		(net "GND")
	)
	(via
		(at 197.637146 -195.616576)
		(size 0.4572)
		(drill 0.2032)
		(layers "F.Cu" "B.Cu")
		(net "GND")
	)
	(via
		(at 119.628666 -213.732618)
		(size 0.4572)
		(drill 0.2032)
		(layers "F.Cu" "B.Cu")
		(net "GND")
	)
	(via
		(at 338.544916 -272.639282)
		(size 0.4572)
		(drill 0.2032)
		(layers "F.Cu" "B.Cu")
		(net "GND")
	)
	(via
		(at 285.150814 -199.01662)
		(size 0.4572)
		(drill 0.2032)
		(layers "F.Cu" "B.Cu")
		(net "GND")
	)
	(via
		(at 78.250034 -432.451256)
		(size 0.4572)
		(drill 0.2032)
		(layers "F.Cu" "B.Cu")
		(net "GND")
	)
	(via
		(at 445.577214 -301.866808)
		(size 0.4572)
		(drill 0.2032)
		(layers "F.Cu" "B.Cu")
		(net "GND")
	)
	(via
		(at 136.619742 -406.370536)
		(size 0.4572)
		(drill 0.254)
		(layers "F.Cu" "B.Cu")
		(net "GND")
	)
	(via
		(at 415.003488 -6.586474)
		(size 0.508)
		(drill 0.254)
		(layers "F.Cu" "B.Cu")
		(net "GND")
	)
	(via
		(at 131.75869 -114.920268)
		(size 0.508)
		(drill 0.254)
		(layers "F.Cu" "B.Cu")
		(net "GND")
	)
	(via
		(at 374.727216 -278.336502)
		(size 0.4572)
		(drill 0.2032)
		(layers "F.Cu" "B.Cu")
		(net "GND")
	)
	(via
		(at 24.223726 -5.596636)
		(size 0.508)
		(drill 0.254)
		(layers "F.Cu" "B.Cu")
		(net "GND")
	)
	(via
		(at 414.646618 -149.312376)
		(size 0.508)
		(drill 0.254)
		(layers "F.Cu" "B.Cu")
		(net "GND")
	)
	(via
		(at 368.50828 -230.086662)
		(size 0.4572)
		(drill 0.2032)
		(layers "F.Cu" "B.Cu")
		(net "GND")
	)
	(via
		(at 189.226698 -12.461748)
		(size 0.508)
		(drill 0.254)
		(layers "F.Cu" "B.Cu")
		(net "GND")
	)
	(via
		(at 327.30567 -341.85225)
		(size 0.49022)
		(drill 0.254)
		(layers "F.Cu" "B.Cu")
		(net "GND")
	)
	(via
		(at 274.163282 -219.41663)
		(size 0.4572)
		(drill 0.2032)
		(layers "F.Cu" "B.Cu")
		(net "GND")
	)
	(via
		(at 405.93137 -4.317746)
		(size 0.508)
		(drill 0.254)
		(layers "F.Cu" "B.Cu")
		(net "GND")
	)
	(via
		(at 277.607014 -250.016772)
		(size 0.4572)
		(drill 0.2032)
		(layers "F.Cu" "B.Cu")
		(net "GND")
	)
	(via
		(at 101.412294 -258.80314)
		(size 0.4572)
		(drill 0.2032)
		(layers "F.Cu" "B.Cu")
		(net "GND")
	)
	(via
		(at 356.214426 -326.948292)
		(size 0.508)
		(drill 0.254)
		(layers "F.Cu" "B.Cu")
		(net "GND")
	)
	(via
		(at 409.748482 -222.816674)
		(size 0.4572)
		(drill 0.2032)
		(layers "F.Cu" "B.Cu")
		(net "GND")
	)
	(via
		(at 311.882282 -266.1666)
		(size 0.4572)
		(drill 0.2032)
		(layers "F.Cu" "B.Cu")
		(net "GND")
	)
	(via
		(at 294.904414 -210.916774)
		(size 0.4572)
		(drill 0.2032)
		(layers "F.Cu" "B.Cu")
		(net "GND")
	)
	(via
		(at 419.636702 -133.94055)
		(size 0.508)
		(drill 0.254)
		(layers "F.Cu" "B.Cu")
		(net "GND")
	)
	(via
		(at 334.675734 -221.94774)
		(size 0.4318)
		(drill 0.2032)
		(layers "F.Cu" "B.Cu")
		(net "GND")
	)
	(via
		(at 453.121014 -225.36658)
		(size 0.4572)
		(drill 0.2032)
		(layers "F.Cu" "B.Cu")
		(net "GND")
	)
	(via
		(at 109.870494 -276.708616)
		(size 0.4572)
		(drill 0.2032)
		(layers "F.Cu" "B.Cu")
		(net "GND")
	)
	(via
		(at 401.857718 -404.51786)
		(size 0.4572)
		(drill 0.254)
		(layers "F.Cu" "B.Cu")
		(net "GND")
	)
	(via
		(at 388.349998 -434.899562)
		(size 0.4572)
		(drill 0.2032)
		(layers "F.Cu" "B.Cu")
		(net "GND")
	)
	(via
		(at 372.26748 -241.481102)
		(size 0.4572)
		(drill 0.2032)
		(layers "F.Cu" "B.Cu")
		(net "GND")
	)
	(via
		(at 344.653362 -289.807142)
		(size 0.4572)
		(drill 0.2032)
		(layers "F.Cu" "B.Cu")
		(net "GND")
	)
	(via
		(at 209.54492 -103.95204)
		(size 0.508)
		(drill 0.254)
		(layers "F.Cu" "B.Cu")
		(net "GND")
	)
	(via
		(at 92.954348 -279.964134)
		(size 0.4572)
		(drill 0.2032)
		(layers "F.Cu" "B.Cu")
		(net "GND")
	)
	(via
		(at 49.666906 -7.215124)
		(size 0.508)
		(drill 0.254)
		(layers "F.Cu" "B.Cu")
		(net "GND")
	)
	(via
		(at 377.266454 -357.998268)
		(size 0.508)
		(drill 0.254)
		(layers "F.Cu" "B.Cu")
		(net "GND")
	)
	(via
		(at 121.47296 -16.91005)
		(size 0.508)
		(drill 0.254)
		(layers "F.Cu" "B.Cu")
		(net "GND")
	)
	(via
		(at 443.367414 -317.166752)
		(size 0.4572)
		(drill 0.2032)
		(layers "F.Cu" "B.Cu")
		(net "GND")
	)
	(via
		(at 46.964346 -267.016738)
		(size 0.4572)
		(drill 0.2032)
		(layers "F.Cu" "B.Cu")
		(net "GND")
	)
	(via
		(at 116.415058 -329.22972)
		(size 0.508)
		(drill 0.254)
		(layers "F.Cu" "B.Cu")
		(net "GND")
	)
	(via
		(at 2.764536 -132.510022)
		(size 0.508)
		(drill 0.254)
		(layers "F.Cu" "B.Cu")
		(net "GND")
	)
	(via
		(at 108.930694 -275.08073)
		(size 0.4572)
		(drill 0.2032)
		(layers "F.Cu" "B.Cu")
		(net "GND")
	)
	(via
		(at 109.591348 -102.293166)
		(size 0.508)
		(drill 0.254)
		(layers "F.Cu" "B.Cu")
		(net "GND")
	)
	(via
		(at 387.30428 -234.970066)
		(size 0.4572)
		(drill 0.2032)
		(layers "F.Cu" "B.Cu")
		(net "GND")
	)
	(via
		(at 251.58573 -54.082442)
		(size 0.508)
		(drill 0.254)
		(layers "F.Cu" "B.Cu")
		(net "GND")
	)
	(via
		(at 458.093318 -379.874018)
		(size 0.508)
		(drill 0.254)
		(layers "F.Cu" "B.Cu")
		(net "GND")
	)
	(via
		(at 442.133482 -250.866656)
		(size 0.4572)
		(drill 0.2032)
		(layers "F.Cu" "B.Cu")
		(net "GND")
	)
	(via
		(at 87.675466 -246.364506)
		(size 0.4572)
		(drill 0.2032)
		(layers "F.Cu" "B.Cu")
		(net "GND")
	)
	(via
		(at 134.195566 -243.922804)
		(size 0.4572)
		(drill 0.2032)
		(layers "F.Cu" "B.Cu")
		(net "GND")
	)
	(via
		(at 261.285482 -312.91657)
		(size 0.4572)
		(drill 0.2032)
		(layers "F.Cu" "B.Cu")
		(net "GND")
	)
	(via
		(at 23.041102 -403.822408)
		(size 0.508)
		(drill 0.254)
		(layers "F.Cu" "B.Cu")
		(net "GND")
	)
	(via
		(at 205.180946 -268.71676)
		(size 0.4572)
		(drill 0.2032)
		(layers "F.Cu" "B.Cu")
		(net "GND")
	)
	(via
		(at 177.75555 -110.975394)
		(size 0.4572)
		(drill 0.254)
		(layers "F.Cu" "B.Cu")
		(net "GND")
	)
	(via
		(at 172.795946 -208.366614)
		(size 0.4572)
		(drill 0.2032)
		(layers "F.Cu" "B.Cu")
		(net "GND")
	)
	(via
		(at 447.467482 -284.866588)
		(size 0.4572)
		(drill 0.2032)
		(layers "F.Cu" "B.Cu")
		(net "GND")
	)
	(via
		(at 129.496312 -229.272846)
		(size 0.4572)
		(drill 0.2032)
		(layers "F.Cu" "B.Cu")
		(net "GND")
	)
	(via
		(at 62.051946 -261.916672)
		(size 0.4572)
		(drill 0.2032)
		(layers "F.Cu" "B.Cu")
		(net "GND")
	)
	(via
		(at 54.508146 -246.616728)
		(size 0.4572)
		(drill 0.2032)
		(layers "F.Cu" "B.Cu")
		(net "GND")
	)
	(via
		(at 122.66168 -101.10724)
		(size 0.508)
		(drill 0.254)
		(layers "F.Cu" "B.Cu")
		(net "GND")
	)
	(via
		(at 88.145366 -248.806208)
		(size 0.4572)
		(drill 0.2032)
		(layers "F.Cu" "B.Cu")
		(net "GND")
	)
	(via
		(at 134.349998 -437.49976)
		(size 0.4572)
		(drill 0.2032)
		(layers "F.Cu" "B.Cu")
		(net "GND")
	)
	(via
		(at 346.20962 -410.664152)
		(size 0.4572)
		(drill 0.254)
		(layers "F.Cu" "B.Cu")
		(net "GND")
	)
	(via
		(at 28.798266 -19.13636)
		(size 0.508)
		(drill 0.254)
		(layers "F.Cu" "B.Cu")
		(net "GND")
	)
	(via
		(at 439.893964 -441.225432)
		(size 0.508)
		(drill 0.254)
		(layers "F.Cu" "B.Cu")
		(net "GND")
	)
	(via
		(at 87.675466 -218.692222)
		(size 0.4572)
		(drill 0.2032)
		(layers "F.Cu" "B.Cu")
		(net "GND")
	)
	(via
		(at 66.152014 -224.516696)
		(size 0.4572)
		(drill 0.2032)
		(layers "F.Cu" "B.Cu")
		(net "GND")
	)
	(via
		(at 405.648414 -231.316784)
		(size 0.4572)
		(drill 0.2032)
		(layers "F.Cu" "B.Cu")
		(net "GND")
	)
	(via
		(at 66.161666 -400.200368)
		(size 0.4572)
		(drill 0.254)
		(layers "F.Cu" "B.Cu")
		(net "GND")
	)
	(via
		(at 123.857766 -222.761556)
		(size 0.4572)
		(drill 0.2032)
		(layers "F.Cu" "B.Cu")
		(net "GND")
	)
	(via
		(at 285.150814 -315.46673)
		(size 0.4572)
		(drill 0.2032)
		(layers "F.Cu" "B.Cu")
		(net "GND")
	)
	(via
		(at 153.34996 -427.699678)
		(size 0.4572)
		(drill 0.2032)
		(layers "F.Cu" "B.Cu")
		(net "GND")
	)
	(via
		(at 199.42429 -71.582788)
		(size 0.508)
		(drill 0.254)
		(layers "F.Cu" "B.Cu")
		(net "GND")
	)
	(via
		(at 373.677434 -234.15625)
		(size 0.4572)
		(drill 0.2032)
		(layers "F.Cu" "B.Cu")
		(net "GND")
	)
	(via
		(at 306.548282 -245.76659)
		(size 0.4572)
		(drill 0.2032)
		(layers "F.Cu" "B.Cu")
		(net "GND")
	)
	(via
		(at 385.237482 -70.722998)
		(size 0.508)
		(drill 0.254)
		(layers "F.Cu" "B.Cu")
		(net "GND")
	)
	(via
		(at 299.004482 -258.516628)
		(size 0.4572)
		(drill 0.2032)
		(layers "F.Cu" "B.Cu")
		(net "GND")
	)
	(via
		(at 155.349956 -429.147224)
		(size 0.4572)
		(drill 0.2032)
		(layers "F.Cu" "B.Cu")
		(net "GND")
	)
	(via
		(at 182.675276 -43.918886)
		(size 0.508)
		(drill 0.254)
		(layers "F.Cu" "B.Cu")
		(net "GND")
	)
	(via
		(at 30.53715 -131.157472)
		(size 0.508)
		(drill 0.254)
		(layers "F.Cu" "B.Cu")
		(net "GND")
	)
	(via
		(at 369.558062 -282.405836)
		(size 0.4572)
		(drill 0.2032)
		(layers "F.Cu" "B.Cu")
		(net "GND")
	)
	(via
		(at 177.23358 -426.92574)
		(size 0.508)
		(drill 0.254)
		(layers "F.Cu" "B.Cu")
		(net "GND")
	)
	(via
		(at 202.971146 -201.56678)
		(size 0.4572)
		(drill 0.2032)
		(layers "F.Cu" "B.Cu")
		(net "GND")
	)
	(via
		(at 99.532948 -273.453098)
		(size 0.4572)
		(drill 0.2032)
		(layers "F.Cu" "B.Cu")
		(net "GND")
	)
	(via
		(at 462.555082 -269.566644)
		(size 0.4572)
		(drill 0.2032)
		(layers "F.Cu" "B.Cu")
		(net "GND")
	)
	(via
		(at 339.37448 -236.597952)
		(size 0.4572)
		(drill 0.2032)
		(layers "F.Cu" "B.Cu")
		(net "GND")
	)
	(via
		(at 373.677434 -222.761556)
		(size 0.4572)
		(drill 0.2032)
		(layers "F.Cu" "B.Cu")
		(net "GND")
	)
	(via
		(at 212.724746 -304.416714)
		(size 0.4572)
		(drill 0.2032)
		(layers "F.Cu" "B.Cu")
		(net "GND")
	)
	(via
		(at 52.082446 -295.06672)
		(size 0.4572)
		(drill 0.2032)
		(layers "F.Cu" "B.Cu")
		(net "GND")
	)
	(via
		(at 373.317516 -257.98907)
		(size 0.4572)
		(drill 0.2032)
		(layers "F.Cu" "B.Cu")
		(net "GND")
	)
	(via
		(at 439.923682 -215.166702)
		(size 0.4572)
		(drill 0.2032)
		(layers "F.Cu" "B.Cu")
		(net "GND")
	)
	(via
		(at 281.707082 -275.516594)
		(size 0.4572)
		(drill 0.2032)
		(layers "F.Cu" "B.Cu")
		(net "GND")
	)
	(via
		(at 430.489614 -283.166566)
		(size 0.4572)
		(drill 0.2032)
		(layers "F.Cu" "B.Cu")
		(net "GND")
	)
	(via
		(at 41.310814 -235.566712)
		(size 0.4572)
		(drill 0.2032)
		(layers "F.Cu" "B.Cu")
		(net "GND")
	)
	(via
		(at 209.281014 -258.516628)
		(size 0.4572)
		(drill 0.2032)
		(layers "F.Cu" "B.Cu")
		(net "GND")
	)
	(via
		(at 27.662886 -163.303204)
		(size 0.508)
		(drill 0.254)
		(layers "F.Cu" "B.Cu")
		(net "GND")
	)
	(via
		(at 139.595606 -404.51786)
		(size 0.4572)
		(drill 0.254)
		(layers "F.Cu" "B.Cu")
		(net "GND")
	)
	(via
		(at 167.461946 -268.71676)
		(size 0.4572)
		(drill 0.2032)
		(layers "F.Cu" "B.Cu")
		(net "GND")
	)
	(via
		(at 398.794478 -400.224244)
		(size 0.4572)
		(drill 0.254)
		(layers "F.Cu" "B.Cu")
		(net "GND")
	)
	(via
		(at 428.279814 -265.316716)
		(size 0.4572)
		(drill 0.2032)
		(layers "F.Cu" "B.Cu")
		(net "GND")
	)
	(via
		(at 121.498614 -333.355188)
		(size 0.49022)
		(drill 0.254)
		(layers "F.Cu" "B.Cu")
		(net "GND")
	)
	(via
		(at 438.033414 -317.166752)
		(size 0.4572)
		(drill 0.2032)
		(layers "F.Cu" "B.Cu")
		(net "GND")
	)
	(via
		(at 266.619482 -308.666642)
		(size 0.4572)
		(drill 0.2032)
		(layers "F.Cu" "B.Cu")
		(net "GND")
	)
	(via
		(at 438.033414 -273.816572)
		(size 0.4572)
		(drill 0.2032)
		(layers "F.Cu" "B.Cu")
		(net "GND")
	)
	(via
		(at 126.350014 -429.147224)
		(size 0.4572)
		(drill 0.2032)
		(layers "F.Cu" "B.Cu")
		(net "GND")
	)
	(via
		(at 95.3897 -422.161208)
		(size 0.508)
		(drill 0.254)
		(layers "F.Cu" "B.Cu")
		(net "GND")
	)
	(via
		(at 29.666946 -298.466764)
		(size 0.4572)
		(drill 0.2032)
		(layers "F.Cu" "B.Cu")
		(net "GND")
	)
	(via
		(at 113.629694 -271.825212)
		(size 0.4572)
		(drill 0.2032)
		(layers "F.Cu" "B.Cu")
		(net "GND")
	)
	(via
		(at 347.805248 -330.42352)
		(size 0.508)
		(drill 0.254)
		(layers "F.Cu" "B.Cu")
		(net "GND")
	)
	(via
		(at 145.349976 -426.54728)
		(size 0.4572)
		(drill 0.2032)
		(layers "F.Cu" "B.Cu")
		(net "GND")
	)
	(via
		(at 349.71228 -238.225584)
		(size 0.4572)
		(drill 0.2032)
		(layers "F.Cu" "B.Cu")
		(net "GND")
	)
	(via
		(at 52.298346 -287.416748)
		(size 0.4572)
		(drill 0.2032)
		(layers "F.Cu" "B.Cu")
		(net "GND")
	)
	(via
		(at 28.433014 -211.766658)
		(size 0.4572)
		(drill 0.2032)
		(layers "F.Cu" "B.Cu")
		(net "GND")
	)
	(via
		(at 46.553882 -352.548698)
		(size 0.508)
		(drill 0.254)
		(layers "F.Cu" "B.Cu")
		(net "GND")
	)
	(via
		(at 408.9654 -184.188608)
		(size 0.508)
		(drill 0.254)
		(layers "F.Cu" "B.Cu")
		(net "GND")
	)
	(via
		(at 405.429212 -313.766708)
		(size 0.4572)
		(drill 0.2032)
		(layers "F.Cu" "B.Cu")
		(net "GND")
	)
	(via
		(at 372.484142 -404.51786)
		(size 0.4572)
		(drill 0.254)
		(layers "F.Cu" "B.Cu")
		(net "GND")
	)
	(via
		(at 29.666946 -265.316716)
		(size 0.4572)
		(drill 0.2032)
		(layers "F.Cu" "B.Cu")
		(net "GND")
	)
	(via
		(at 344.183462 -272.639282)
		(size 0.4572)
		(drill 0.2032)
		(layers "F.Cu" "B.Cu")
		(net "GND")
	)
	(via
		(at 195.427346 -240.666778)
		(size 0.4572)
		(drill 0.2032)
		(layers "F.Cu" "B.Cu")
		(net "GND")
	)
	(via
		(at 376.136662 -284.033722)
		(size 0.4572)
		(drill 0.2032)
		(layers "F.Cu" "B.Cu")
		(net "GND")
	)
	(via
		(at 28.433014 -261.066788)
		(size 0.4572)
		(drill 0.2032)
		(layers "F.Cu" "B.Cu")
		(net "GND")
	)
	(via
		(at 333.375762 -283.219906)
		(size 0.4572)
		(drill 0.2032)
		(layers "F.Cu" "B.Cu")
		(net "GND")
	)
	(via
		(at 80.766666 -348.296992)
		(size 0.508)
		(drill 0.254)
		(layers "F.Cu" "B.Cu")
		(net "GND")
	)
	(via
		(at 62.267846 -276.366732)
		(size 0.4572)
		(drill 0.2032)
		(layers "F.Cu" "B.Cu")
		(net "GND")
	)
	(via
		(at 427.045882 -241.516662)
		(size 0.4572)
		(drill 0.2032)
		(layers "F.Cu" "B.Cu")
		(net "GND")
	)
	(via
		(at 101.617018 -329.722226)
		(size 0.508)
		(drill 0.254)
		(layers "F.Cu" "B.Cu")
		(net "GND")
	)
	(via
		(at 61.655198 -400.858228)
		(size 0.4064)
		(drill 0.2032)
		(layers "F.Cu" "B.Cu")
		(net "GND")
	)
	(via
		(at 24.332946 -290.816792)
		(size 0.4572)
		(drill 0.2032)
		(layers "F.Cu" "B.Cu")
		(net "GND")
	)
	(via
		(at 337.882992 -82.72018)
		(size 0.508)
		(drill 0.254)
		(layers "F.Cu" "B.Cu")
		(net "GND")
	)
	(via
		(at 259.075682 -303.566576)
		(size 0.4572)
		(drill 0.2032)
		(layers "F.Cu" "B.Cu")
		(net "GND")
	)
	(via
		(at 268.829282 -205.816708)
		(size 0.4572)
		(drill 0.2032)
		(layers "F.Cu" "B.Cu")
		(net "GND")
	)
	(via
		(at 167.461946 -221.96679)
		(size 0.4572)
		(drill 0.2032)
		(layers "F.Cu" "B.Cu")
		(net "GND")
	)
	(via
		(at 32.100266 -18.246344)
		(size 0.508)
		(drill 0.254)
		(layers "F.Cu" "B.Cu")
		(net "GND")
	)
	(via
		(at 257.185414 -296.766742)
		(size 0.4572)
		(drill 0.2032)
		(layers "F.Cu" "B.Cu")
		(net "GND")
	)
	(via
		(at 35.976814 -196.466714)
		(size 0.4572)
		(drill 0.2032)
		(layers "F.Cu" "B.Cu")
		(net "GND")
	)
	(via
		(at 413.192214 -223.666558)
		(size 0.4572)
		(drill 0.2032)
		(layers "F.Cu" "B.Cu")
		(net "GND")
	)
	(via
		(at 367.568734 -217.064336)
		(size 0.4572)
		(drill 0.2032)
		(layers "F.Cu" "B.Cu")
		(net "GND")
	)
	(via
		(at 414.756854 -12.37488)
		(size 0.508)
		(drill 0.254)
		(layers "F.Cu" "B.Cu")
		(net "GND")
	)
	(via
		(at 304.338482 -289.966654)
		(size 0.4572)
		(drill 0.2032)
		(layers "F.Cu" "B.Cu")
		(net "GND")
	)
	(via
		(at 308.501542 -37.822886)
		(size 0.508)
		(drill 0.254)
		(layers "F.Cu" "B.Cu")
		(net "GND")
	)
	(via
		(at 377.90628 -244.73662)
		(size 0.4572)
		(drill 0.2032)
		(layers "F.Cu" "B.Cu")
		(net "GND")
	)
	(via
		(at 283.916882 -306.96662)
		(size 0.4572)
		(drill 0.2032)
		(layers "F.Cu" "B.Cu")
		(net "GND")
	)
	(via
		(at 349.634048 -406.980644)
		(size 0.4064)
		(drill 0.2032)
		(layers "F.Cu" "B.Cu")
		(net "GND")
	)
	(via
		(at 194.193414 -295.916604)
		(size 0.4572)
		(drill 0.2032)
		(layers "F.Cu" "B.Cu")
		(net "GND")
	)
	(via
		(at 155.349956 -431.451258)
		(size 0.4572)
		(drill 0.2032)
		(layers "F.Cu" "B.Cu")
		(net "GND")
	)
	(via
		(at 382.19888 -340.904322)
		(size 0.508)
		(drill 0.254)
		(layers "F.Cu" "B.Cu")
		(net "GND")
	)
	(via
		(at 82.824066 -409.396184)
		(size 0.4572)
		(drill 0.254)
		(layers "F.Cu" "B.Cu")
		(net "GND")
	)
	(via
		(at 171.869608 -291.666676)
		(size 0.4572)
		(drill 0.2032)
		(layers "F.Cu" "B.Cu")
		(net "GND")
	)
	(via
		(at 261.285482 -261.066788)
		(size 0.4572)
		(drill 0.2032)
		(layers "F.Cu" "B.Cu")
		(net "GND")
	)
	(via
		(at 274.163282 -226.216718)
		(size 0.4572)
		(drill 0.2032)
		(layers "F.Cu" "B.Cu")
		(net "GND")
	)
	(via
		(at 121.617994 -272.639282)
		(size 0.4572)
		(drill 0.2032)
		(layers "F.Cu" "B.Cu")
		(net "GND")
	)
	(via
		(at 403.589998 -4.317746)
		(size 0.508)
		(drill 0.254)
		(layers "F.Cu" "B.Cu")
		(net "GND")
	)
	(via
		(at 23.946866 -12.37488)
		(size 0.508)
		(drill 0.254)
		(layers "F.Cu" "B.Cu")
		(net "GND")
	)
	(via
		(at 383.655062 -261.244842)
		(size 0.4572)
		(drill 0.2032)
		(layers "F.Cu" "B.Cu")
		(net "GND")
	)
	(via
		(at 281.707082 -239.81664)
		(size 0.4572)
		(drill 0.2032)
		(layers "F.Cu" "B.Cu")
		(net "GND")
	)
	(via
		(at 415.402014 -244.916706)
		(size 0.4572)
		(drill 0.2032)
		(layers "F.Cu" "B.Cu")
		(net "GND")
	)
	(via
		(at 128.287526 -335.976214)
		(size 0.49022)
		(drill 0.254)
		(layers "F.Cu" "B.Cu")
		(net "GND")
	)
	(via
		(at 412.956756 -12.37488)
		(size 0.508)
		(drill 0.254)
		(layers "F.Cu" "B.Cu")
		(net "GND")
	)
	(via
		(at 448.1576 -14.595348)
		(size 0.508)
		(drill 0.254)
		(layers "F.Cu" "B.Cu")
		(net "GND")
	)
	(via
		(at 161.808414 -233.86669)
		(size 0.4572)
		(drill 0.2032)
		(layers "F.Cu" "B.Cu")
		(net "GND")
	)
	(via
		(at 71.82993 -410.664152)
		(size 0.4572)
		(drill 0.254)
		(layers "F.Cu" "B.Cu")
		(net "GND")
	)
	(via
		(at 289.250882 -198.166736)
		(size 0.4572)
		(drill 0.2032)
		(layers "F.Cu" "B.Cu")
		(net "GND")
	)
	(via
		(at 205.180946 -290.816792)
		(size 0.4572)
		(drill 0.2032)
		(layers "F.Cu" "B.Cu")
		(net "GND")
	)
	(via
		(at 306.548282 -202.416664)
		(size 0.4572)
		(drill 0.2032)
		(layers "F.Cu" "B.Cu")
		(net "GND")
	)
	(via
		(at 434.589682 -306.96662)
		(size 0.4572)
		(drill 0.2032)
		(layers "F.Cu" "B.Cu")
		(net "GND")
	)
	(via
		(at 129.74701 -12.495276)
		(size 0.508)
		(drill 0.254)
		(layers "F.Cu" "B.Cu")
		(net "GND")
	)
	(via
		(at 197.637146 -201.56678)
		(size 0.4572)
		(drill 0.2032)
		(layers "F.Cu" "B.Cu")
		(net "GND")
	)
	(via
		(at 177.06848 -103.698548)
		(size 0.508)
		(drill 0.254)
		(layers "F.Cu" "B.Cu")
		(net "GND")
	)
	(via
		(at 62.051946 -214.316564)
		(size 0.4572)
		(drill 0.2032)
		(layers "F.Cu" "B.Cu")
		(net "GND")
	)
	(via
		(at 309.992014 -248.31675)
		(size 0.4572)
		(drill 0.2032)
		(layers "F.Cu" "B.Cu")
		(net "GND")
	)
	(via
		(at 364.383828 -331.264514)
		(size 0.508)
		(drill 0.254)
		(layers "F.Cu" "B.Cu")
		(net "GND")
	)
	(via
		(at 209.281014 -249.166634)
		(size 0.4572)
		(drill 0.2032)
		(layers "F.Cu" "B.Cu")
		(net "GND")
	)
	(via
		(at 112.110266 -217.064336)
		(size 0.4572)
		(drill 0.2032)
		(layers "F.Cu" "B.Cu")
		(net "GND")
	)
	(via
		(at 136.545066 -226.831144)
		(size 0.4318)
		(drill 0.2032)
		(layers "F.Cu" "B.Cu")
		(net "GND")
	)
	(via
		(at 380.365762 -276.708616)
		(size 0.4572)
		(drill 0.2032)
		(layers "F.Cu" "B.Cu")
		(net "GND")
	)
	(via
		(at 122.557794 -264.50036)
		(size 0.4572)
		(drill 0.2032)
		(layers "F.Cu" "B.Cu")
		(net "GND")
	)
	(via
		(at 457.221082 -239.81664)
		(size 0.4572)
		(drill 0.2032)
		(layers "F.Cu" "B.Cu")
		(net "GND")
	)
	(via
		(at 132.895594 -282.405836)
		(size 0.4572)
		(drill 0.2032)
		(layers "F.Cu" "B.Cu")
		(net "GND")
	)
	(via
		(at 129.242312 -357.47579)
		(size 0.508)
		(drill 0.254)
		(layers "F.Cu" "B.Cu")
		(net "GND")
	)
	(via
		(at 375.557034 -219.506038)
		(size 0.4572)
		(drill 0.2032)
		(layers "F.Cu" "B.Cu")
		(net "GND")
	)
	(via
		(at 424.836082 -277.216616)
		(size 0.4572)
		(drill 0.2032)
		(layers "F.Cu" "B.Cu")
		(net "GND")
	)
	(via
		(at 298.442888 -360.83621)
		(size 0.49022)
		(drill 0.254)
		(layers "F.Cu" "B.Cu")
		(net "GND")
	)
	(via
		(at 373.787416 -283.219906)
		(size 0.4572)
		(drill 0.2032)
		(layers "F.Cu" "B.Cu")
		(net "GND")
	)
	(via
		(at 96.603566 -222.761556)
		(size 0.4572)
		(drill 0.2032)
		(layers "F.Cu" "B.Cu")
		(net "GND")
	)
	(via
		(at 24.332946 -304.416714)
		(size 0.4572)
		(drill 0.2032)
		(layers "F.Cu" "B.Cu")
		(net "GND")
	)
	(via
		(at 33.767014 -316.316614)
		(size 0.4572)
		(drill 0.2032)
		(layers "F.Cu" "B.Cu")
		(net "GND")
	)
	(via
		(at 175.005746 -201.56678)
		(size 0.4572)
		(drill 0.2032)
		(layers "F.Cu" "B.Cu")
		(net "GND")
	)
	(via
		(at 347.363034 -226.017328)
		(size 0.4572)
		(drill 0.2032)
		(layers "F.Cu" "B.Cu")
		(net "GND")
	)
	(via
		(at 130.436366 -222.761556)
		(size 0.4572)
		(drill 0.2032)
		(layers "F.Cu" "B.Cu")
		(net "GND")
	)
	(via
		(at 384.594862 -267.755878)
		(size 0.4572)
		(drill 0.2032)
		(layers "F.Cu" "B.Cu")
		(net "GND")
	)
	(via
		(at 59.842146 -214.316564)
		(size 0.4572)
		(drill 0.2032)
		(layers "F.Cu" "B.Cu")
		(net "GND")
	)
	(via
		(at 411.047438 -400.224244)
		(size 0.4572)
		(drill 0.254)
		(layers "F.Cu" "B.Cu")
		(net "GND")
	)
	(via
		(at 7.035546 -285.716726)
		(size 0.4572)
		(drill 0.2032)
		(layers "F.Cu" "B.Cu")
		(net "GND")
	)
	(via
		(at 384.124962 -257.175254)
		(size 0.4572)
		(drill 0.2032)
		(layers "F.Cu" "B.Cu")
		(net "GND")
	)
	(via
		(at 65.328038 -323.50456)
		(size 0.4572)
		(drill 0.2032)
		(layers "F.Cu" "B.Cu")
		(net "GND")
	)
	(via
		(at 214.615014 -278.916638)
		(size 0.4572)
		(drill 0.2032)
		(layers "F.Cu" "B.Cu")
		(net "GND")
	)
	(via
		(at 29.666946 -246.616728)
		(size 0.4572)
		(drill 0.2032)
		(layers "F.Cu" "B.Cu")
		(net "GND")
	)
	(via
		(at 414.85947 -162.217354)
		(size 0.49022)
		(drill 0.254)
		(layers "F.Cu" "B.Cu")
		(net "GND")
	)
	(via
		(at 84.856066 -243.108988)
		(size 0.4572)
		(drill 0.2032)
		(layers "F.Cu" "B.Cu")
		(net "GND")
	)
	(via
		(at 135.714994 -261.244842)
		(size 0.4572)
		(drill 0.2032)
		(layers "F.Cu" "B.Cu")
		(net "GND")
	)
	(via
		(at 18.679414 -245.76659)
		(size 0.4572)
		(drill 0.2032)
		(layers "F.Cu" "B.Cu")
		(net "GND")
	)
	(via
		(at 338.099908 -49.650396)
		(size 0.4572)
		(drill 0.2032)
		(layers "F.Cu" "B.Cu")
		(net "GND")
	)
	(via
		(at 407.858214 -276.366732)
		(size 0.4572)
		(drill 0.2032)
		(layers "F.Cu" "B.Cu")
		(net "GND")
	)
	(via
		(at 299.004482 -241.516662)
		(size 0.4572)
		(drill 0.2032)
		(layers "F.Cu" "B.Cu")
		(net "GND")
	)
	(via
		(at 7.264654 -426.095414)
		(size 0.508)
		(drill 0.254)
		(layers "F.Cu" "B.Cu")
		(net "GND")
	)
	(via
		(at 186.649614 -204.116686)
		(size 0.4572)
		(drill 0.2032)
		(layers "F.Cu" "B.Cu")
		(net "GND")
	)
	(via
		(at 354.051362 -283.219906)
		(size 0.4572)
		(drill 0.2032)
		(layers "F.Cu" "B.Cu")
		(net "GND")
	)
	(via
		(at 171.562014 -288.266632)
		(size 0.4572)
		(drill 0.2032)
		(layers "F.Cu" "B.Cu")
		(net "GND")
	)
	(via
		(at 134.501382 -76.073)
		(size 0.508)
		(drill 0.254)
		(layers "F.Cu" "B.Cu")
		(net "GND")
	)
	(via
		(at 97.073466 -230.086662)
		(size 0.4572)
		(drill 0.2032)
		(layers "F.Cu" "B.Cu")
		(net "GND")
	)
	(via
		(at 89.664794 -275.8948)
		(size 0.4572)
		(drill 0.2032)
		(layers "F.Cu" "B.Cu")
		(net "GND")
	)
	(via
		(at 209.281014 -306.96662)
		(size 0.4572)
		(drill 0.2032)
		(layers "F.Cu" "B.Cu")
		(net "GND")
	)
	(via
		(at 336.55508 -217.064336)
		(size 0.4572)
		(drill 0.2032)
		(layers "F.Cu" "B.Cu")
		(net "GND")
	)
	(via
		(at 448.205352 -323.429376)
		(size 0.4572)
		(drill 0.2032)
		(layers "F.Cu" "B.Cu")
		(net "GND")
	)
	(via
		(at 164.018214 -228.766624)
		(size 0.4572)
		(drill 0.2032)
		(layers "F.Cu" "B.Cu")
		(net "GND")
	)
	(via
		(at 430.489614 -311.216802)
		(size 0.4572)
		(drill 0.2032)
		(layers "F.Cu" "B.Cu")
		(net "GND")
	)
	(via
		(at 124.907548 -281.59202)
		(size 0.4572)
		(drill 0.2032)
		(layers "F.Cu" "B.Cu")
		(net "GND")
	)
	(via
		(at 59.250072 -430.299622)
		(size 0.4572)
		(drill 0.2032)
		(layers "F.Cu" "B.Cu")
		(net "GND")
	)
	(via
		(at 401.823174 -4.95173)
		(size 0.508)
		(drill 0.254)
		(layers "F.Cu" "B.Cu")
		(net "GND")
	)
	(via
		(at 311.882282 -204.116686)
		(size 0.4572)
		(drill 0.2032)
		(layers "F.Cu" "B.Cu")
		(net "GND")
	)
	(via
		(at 172.795946 -203.266802)
		(size 0.4572)
		(drill 0.2032)
		(layers "F.Cu" "B.Cu")
		(net "GND")
	)
	(via
		(at 84.08289 -410.664152)
		(size 0.4572)
		(drill 0.254)
		(layers "F.Cu" "B.Cu")
		(net "GND")
	)
	(via
		(at 430.272698 -58.464196)
		(size 0.508)
		(drill 0.254)
		(layers "F.Cu" "B.Cu")
		(net "GND")
	)
	(via
		(at 109.77753 -331.703426)
		(size 0.508)
		(drill 0.254)
		(layers "F.Cu" "B.Cu")
		(net "GND")
	)
	(via
		(at 443.367414 -258.516628)
		(size 0.4572)
		(drill 0.2032)
		(layers "F.Cu" "B.Cu")
		(net "GND")
	)
	(via
		(at 347.942662 -284.033722)
		(size 0.4572)
		(drill 0.2032)
		(layers "F.Cu" "B.Cu")
		(net "GND")
	)
	(via
		(at 341.887556 -409.396184)
		(size 0.4572)
		(drill 0.254)
		(layers "F.Cu" "B.Cu")
		(net "GND")
	)
	(via
		(at 64.083438 -407.00452)
		(size 0.4064)
		(drill 0.2032)
		(layers "F.Cu" "B.Cu")
		(net "GND")
	)
	(via
		(at 272.273014 -304.416714)
		(size 0.4572)
		(drill 0.2032)
		(layers "F.Cu" "B.Cu")
		(net "GND")
	)
	(via
		(at 113.629694 -268.569694)
		(size 0.4572)
		(drill 0.2032)
		(layers "F.Cu" "B.Cu")
		(net "GND")
	)
	(via
		(at 341.918798 -48.450246)
		(size 0.4572)
		(drill 0.2032)
		(layers "F.Cu" "B.Cu")
		(net "GND")
	)
	(via
		(at 358.027732 -39.853616)
		(size 0.508)
		(drill 0.254)
		(layers "F.Cu" "B.Cu")
		(net "GND")
	)
	(via
		(at 429.343312 -4.95173)
		(size 0.508)
		(drill 0.254)
		(layers "F.Cu" "B.Cu")
		(net "GND")
	)
	(via
		(at 87.960962 -339.114638)
		(size 0.49022)
		(drill 0.254)
		(layers "F.Cu" "B.Cu")
		(net "GND")
	)
	(via
		(at 462.555082 -314.616592)
		(size 0.4572)
		(drill 0.2032)
		(layers "F.Cu" "B.Cu")
		(net "GND")
	)
	(via
		(at 20.889214 -275.516594)
		(size 0.4572)
		(drill 0.2032)
		(layers "F.Cu" "B.Cu")
		(net "GND")
	)
	(via
		(at 103.652066 -226.831144)
		(size 0.4572)
		(drill 0.2032)
		(layers "F.Cu" "B.Cu")
		(net "GND")
	)
	(via
		(at 302.448214 -197.316598)
		(size 0.4572)
		(drill 0.2032)
		(layers "F.Cu" "B.Cu")
		(net "GND")
	)
	(via
		(at 294.825928 -52.041298)
		(size 0.508)
		(drill 0.254)
		(layers "F.Cu" "B.Cu")
		(net "GND")
	)
	(via
		(at 424.836082 -222.816674)
		(size 0.4572)
		(drill 0.2032)
		(layers "F.Cu" "B.Cu")
		(net "GND")
	)
	(via
		(at 464.764882 -219.41663)
		(size 0.4572)
		(drill 0.2032)
		(layers "F.Cu" "B.Cu")
		(net "GND")
	)
	(via
		(at 337.116928 -403.883876)
		(size 0.4064)
		(drill 0.2032)
		(layers "F.Cu" "B.Cu")
		(net "GND")
	)
	(via
		(at 132.785866 -223.575626)
		(size 0.4572)
		(drill 0.2032)
		(layers "F.Cu" "B.Cu")
		(net "GND")
	)
	(via
		(at 292.694614 -261.916672)
		(size 0.4572)
		(drill 0.2032)
		(layers "F.Cu" "B.Cu")
		(net "GND")
	)
	(via
		(at 445.577214 -281.466798)
		(size 0.4572)
		(drill 0.2032)
		(layers "F.Cu" "B.Cu")
		(net "GND")
	)
	(via
		(at 149.349968 -431.29962)
		(size 0.4572)
		(drill 0.2032)
		(layers "F.Cu" "B.Cu")
		(net "GND")
	)
	(via
		(at 112.40008 -123.148598)
		(size 0.508)
		(drill 0.254)
		(layers "F.Cu" "B.Cu")
		(net "GND")
	)
	(via
		(at 159.918146 -195.616576)
		(size 0.4572)
		(drill 0.2032)
		(layers "F.Cu" "B.Cu")
		(net "GND")
	)
	(via
		(at 431.618136 -4.95173)
		(size 0.508)
		(drill 0.254)
		(layers "F.Cu" "B.Cu")
		(net "GND")
	)
	(via
		(at 434.589682 -215.166702)
		(size 0.4572)
		(drill 0.2032)
		(layers "F.Cu" "B.Cu")
		(net "GND")
	)
	(via
		(at 7.809484 -323.434456)
		(size 0.4572)
		(drill 0.2032)
		(layers "F.Cu" "B.Cu")
		(net "GND")
	)
	(via
		(at 254.975614 -289.11677)
		(size 0.4572)
		(drill 0.2032)
		(layers "F.Cu" "B.Cu")
		(net "GND")
	)
	(via
		(at 126.316994 -271.011396)
		(size 0.4572)
		(drill 0.2032)
		(layers "F.Cu" "B.Cu")
		(net "GND")
	)
	(via
		(at 304.338482 -249.166634)
		(size 0.4572)
		(drill 0.2032)
		(layers "F.Cu" "B.Cu")
		(net "GND")
	)
	(via
		(at 7.035546 -301.866808)
		(size 0.4572)
		(drill 0.2032)
		(layers "F.Cu" "B.Cu")
		(net "GND")
	)
	(via
		(at 368.066828 -332.56601)
		(size 0.49022)
		(drill 0.254)
		(layers "F.Cu" "B.Cu")
		(net "GND")
	)
	(via
		(at 346.063062 -271.011396)
		(size 0.4572)
		(drill 0.2032)
		(layers "F.Cu" "B.Cu")
		(net "GND")
	)
	(via
		(at 274.163282 -233.86669)
		(size 0.4572)
		(drill 0.2032)
		(layers "F.Cu" "B.Cu")
		(net "GND")
	)
	(via
		(at 62.051946 -221.96679)
		(size 0.4572)
		(drill 0.2032)
		(layers "F.Cu" "B.Cu")
		(net "GND")
	)
	(via
		(at 28.433014 -226.216718)
		(size 0.4572)
		(drill 0.2032)
		(layers "F.Cu" "B.Cu")
		(net "GND")
	)
	(via
		(at 407.34996 -429.147224)
		(size 0.4572)
		(drill 0.2032)
		(layers "F.Cu" "B.Cu")
		(net "GND")
	)
	(via
		(at 424.166792 -10.16508)
		(size 0.508)
		(drill 0.254)
		(layers "F.Cu" "B.Cu")
		(net "GND")
	)
	(via
		(at 352.782632 -66.116454)
		(size 0.508)
		(drill 0.254)
		(layers "F.Cu" "B.Cu")
		(net "GND")
	)
	(via
		(at 184.439814 -316.316614)
		(size 0.4572)
		(drill 0.2032)
		(layers "F.Cu" "B.Cu")
		(net "GND")
	)
	(via
		(at 16.789146 -289.11677)
		(size 0.4572)
		(drill 0.2032)
		(layers "F.Cu" "B.Cu")
		(net "GND")
	)
	(via
		(at 422.945814 -197.316598)
		(size 0.4572)
		(drill 0.2032)
		(layers "F.Cu" "B.Cu")
		(net "GND")
	)
	(via
		(at 139.595606 -400.200368)
		(size 0.4572)
		(drill 0.254)
		(layers "F.Cu" "B.Cu")
		(net "GND")
	)
	(via
		(at 62.051946 -292.516814)
		(size 0.4572)
		(drill 0.2032)
		(layers "F.Cu" "B.Cu")
		(net "GND")
	)
	(via
		(at 20.077938 -6.090412)
		(size 0.508)
		(drill 0.254)
		(layers "F.Cu" "B.Cu")
		(net "GND")
	)
	(via
		(at 64.718438 -403.883876)
		(size 0.4064)
		(drill 0.2032)
		(layers "F.Cu" "B.Cu")
		(net "GND")
	)
	(via
		(at 212.724746 -231.316784)
		(size 0.4572)
		(drill 0.2032)
		(layers "F.Cu" "B.Cu")
		(net "GND")
	)
	(via
		(at 85.432138 -342.481662)
		(size 0.508)
		(drill 0.254)
		(layers "F.Cu" "B.Cu")
		(net "GND")
	)
	(via
		(at 119.158766 -219.506038)
		(size 0.4572)
		(drill 0.2032)
		(layers "F.Cu" "B.Cu")
		(net "GND")
	)
	(via
		(at 136.946894 -17.655032)
		(size 0.508)
		(drill 0.254)
		(layers "F.Cu" "B.Cu")
		(net "GND")
	)
	(via
		(at 43.520614 -282.316682)
		(size 0.4572)
		(drill 0.2032)
		(layers "F.Cu" "B.Cu")
		(net "GND")
	)
	(via
		(at 407.362152 -323.378576)
		(size 0.4572)
		(drill 0.2032)
		(layers "F.Cu" "B.Cu")
		(net "GND")
	)
	(via
		(at 18.679414 -267.866622)
		(size 0.4572)
		(drill 0.2032)
		(layers "F.Cu" "B.Cu")
		(net "GND")
	)
	(via
		(at 100.525834 -330.42352)
		(size 0.508)
		(drill 0.254)
		(layers "F.Cu" "B.Cu")
		(net "GND")
	)
	(via
		(at 35.976814 -215.166702)
		(size 0.4572)
		(drill 0.2032)
		(layers "F.Cu" "B.Cu")
		(net "GND")
	)
	(via
		(at 116.127784 -295.03878)
		(size 0.508)
		(drill 0.254)
		(layers "F.Cu" "B.Cu")
		(net "GND")
	)
	(via
		(at 212.724746 -270.416782)
		(size 0.4572)
		(drill 0.2032)
		(layers "F.Cu" "B.Cu")
		(net "GND")
	)
	(via
		(at 123.387612 -234.970066)
		(size 0.4572)
		(drill 0.2032)
		(layers "F.Cu" "B.Cu")
		(net "GND")
	)
	(via
		(at 264.729214 -283.166566)
		(size 0.4572)
		(drill 0.2032)
		(layers "F.Cu" "B.Cu")
		(net "GND")
	)
	(via
		(at 296.794682 -278.916638)
		(size 0.4572)
		(drill 0.2032)
		(layers "F.Cu" "B.Cu")
		(net "GND")
	)
	(via
		(at 418.356796 -7.215124)
		(size 0.508)
		(drill 0.254)
		(layers "F.Cu" "B.Cu")
		(net "GND")
	)
	(via
		(at 420.736014 -212.616796)
		(size 0.4572)
		(drill 0.2032)
		(layers "F.Cu" "B.Cu")
		(net "GND")
	)
	(via
		(at 175.005746 -225.36658)
		(size 0.4572)
		(drill 0.2032)
		(layers "F.Cu" "B.Cu")
		(net "GND")
	)
	(via
		(at 202.62088 -156.936948)
		(size 0.508)
		(drill 0.254)
		(layers "F.Cu" "B.Cu")
		(net "GND")
	)
	(via
		(at 400.24685 -9.424924)
		(size 0.508)
		(drill 0.254)
		(layers "F.Cu" "B.Cu")
		(net "GND")
	)
	(via
		(at 321.250056 -428.851314)
		(size 0.4572)
		(drill 0.2032)
		(layers "F.Cu" "B.Cu")
		(net "GND")
	)
	(via
		(at 448.93357 -76.873354)
		(size 0.508)
		(drill 0.254)
		(layers "F.Cu" "B.Cu")
		(net "GND")
	)
	(via
		(at 202.971146 -214.316564)
		(size 0.4572)
		(drill 0.2032)
		(layers "F.Cu" "B.Cu")
		(net "GND")
	)
	(via
		(at 403.813772 -19.759422)
		(size 0.508)
		(drill 0.254)
		(layers "F.Cu" "B.Cu")
		(net "GND")
	)
	(via
		(at 183.902096 -351.619058)
		(size 0.49022)
		(drill 0.254)
		(layers "F.Cu" "B.Cu")
		(net "GND")
	)
	(via
		(at 207.071214 -213.46668)
		(size 0.4572)
		(drill 0.2032)
		(layers "F.Cu" "B.Cu")
		(net "GND")
	)
	(via
		(at 14.579346 -317.166752)
		(size 0.4572)
		(drill 0.2032)
		(layers "F.Cu" "B.Cu")
		(net "GND")
	)
	(via
		(at 110.340394 -256.361692)
		(size 0.4572)
		(drill 0.2032)
		(layers "F.Cu" "B.Cu")
		(net "GND")
	)
	(via
		(at 306.764182 -291.666676)
		(size 0.4572)
		(drill 0.2032)
		(layers "F.Cu" "B.Cu")
		(net "GND")
	)
	(via
		(at 148.872702 -409.396184)
		(size 0.4572)
		(drill 0.254)
		(layers "F.Cu" "B.Cu")
		(net "GND")
	)
	(via
		(at 157.708346 -292.516814)
		(size 0.4572)
		(drill 0.2032)
		(layers "F.Cu" "B.Cu")
		(net "GND")
	)
	(via
		(at 121.37009 -428.107348)
		(size 0.508)
		(drill 0.254)
		(layers "F.Cu" "B.Cu")
		(net "GND")
	)
	(via
		(at 167.252142 -406.370536)
		(size 0.4572)
		(drill 0.254)
		(layers "F.Cu" "B.Cu")
		(net "GND")
	)
	(via
		(at 348.302834 -226.017328)
		(size 0.4572)
		(drill 0.2032)
		(layers "F.Cu" "B.Cu")
		(net "GND")
	)
	(via
		(at 121.038366 -216.25052)
		(size 0.4572)
		(drill 0.2032)
		(layers "F.Cu" "B.Cu")
		(net "GND")
	)
	(via
		(at 241.643916 -51.774598)
		(size 0.508)
		(drill 0.254)
		(layers "F.Cu" "B.Cu")
		(net "GND")
	)
	(via
		(at 268.829282 -288.266632)
		(size 0.4572)
		(drill 0.2032)
		(layers "F.Cu" "B.Cu")
		(net "GND")
	)
	(via
		(at 43.500548 -366.62106)
		(size 0.508)
		(drill 0.254)
		(layers "F.Cu" "B.Cu")
		(net "GND")
	)
	(via
		(at 141.038834 -403.883876)
		(size 0.4064)
		(drill 0.2032)
		(layers "F.Cu" "B.Cu")
		(net "GND")
	)
	(via
		(at 184.439814 -210.066636)
		(size 0.4572)
		(drill 0.2032)
		(layers "F.Cu" "B.Cu")
		(net "GND")
	)
	(via
		(at 261.285482 -239.81664)
		(size 0.4572)
		(drill 0.2032)
		(layers "F.Cu" "B.Cu")
		(net "GND")
	)
	(via
		(at 449.677282 -310.366664)
		(size 0.4572)
		(drill 0.2032)
		(layers "F.Cu" "B.Cu")
		(net "GND")
	)
	(via
		(at 157.349952 -437.34736)
		(size 0.4572)
		(drill 0.2032)
		(layers "F.Cu" "B.Cu")
		(net "GND")
	)
	(via
		(at 126.65202 -35.684968)
		(size 0.508)
		(drill 0.254)
		(layers "F.Cu" "B.Cu")
		(net "GND")
	)
	(via
		(at 128.284986 -353.828858)
		(size 0.508)
		(drill 0.254)
		(layers "F.Cu" "B.Cu")
		(net "GND")
	)
	(via
		(at 26.223214 -204.116686)
		(size 0.4572)
		(drill 0.2032)
		(layers "F.Cu" "B.Cu")
		(net "GND")
	)
	(via
		(at 66.152014 -306.96662)
		(size 0.4572)
		(drill 0.2032)
		(layers "F.Cu" "B.Cu")
		(net "GND")
	)
	(via
		(at 343.585292 -331.776832)
		(size 0.49022)
		(drill 0.254)
		(layers "F.Cu" "B.Cu")
		(net "GND")
	)
	(via
		(at 450.911214 -268.71676)
		(size 0.4572)
		(drill 0.2032)
		(layers "F.Cu" "B.Cu")
		(net "GND")
	)
	(via
		(at 99.532948 -270.19758)
		(size 0.4572)
		(drill 0.2032)
		(layers "F.Cu" "B.Cu")
		(net "GND")
	)
	(via
		(at 440.09564 -94.663768)
		(size 0.508)
		(drill 0.254)
		(layers "F.Cu" "B.Cu")
		(net "GND")
	)
	(via
		(at 9.245346 -287.416748)
		(size 0.4572)
		(drill 0.2032)
		(layers "F.Cu" "B.Cu")
		(net "GND")
	)
	(via
		(at 48.854614 -224.516696)
		(size 0.4572)
		(drill 0.2032)
		(layers "F.Cu" "B.Cu")
		(net "GND")
	)
	(via
		(at 201.737214 -204.116686)
		(size 0.4572)
		(drill 0.2032)
		(layers "F.Cu" "B.Cu")
		(net "GND")
	)
	(via
		(at 99.24542 -100.292408)
		(size 0.508)
		(drill 0.254)
		(layers "F.Cu" "B.Cu")
		(net "GND")
	)
	(via
		(at 396.349982 -439.651394)
		(size 0.4572)
		(drill 0.2032)
		(layers "F.Cu" "B.Cu")
		(net "GND")
	)
	(via
		(at 338.250022 -437.34736)
		(size 0.4572)
		(drill 0.2032)
		(layers "F.Cu" "B.Cu")
		(net "GND")
	)
	(via
		(at 430.489614 -301.866808)
		(size 0.4572)
		(drill 0.2032)
		(layers "F.Cu" "B.Cu")
		(net "GND")
	)
	(via
		(at 171.827952 -235.566712)
		(size 0.4572)
		(drill 0.2032)
		(layers "F.Cu" "B.Cu")
		(net "GND")
	)
	(via
		(at 363.58322 -63.82131)
		(size 0.508)
		(drill 0.254)
		(layers "F.Cu" "B.Cu")
		(net "GND")
	)
	(via
		(at 145.349976 -431.29962)
		(size 0.4572)
		(drill 0.2032)
		(layers "F.Cu" "B.Cu")
		(net "GND")
	)
	(via
		(at 120.098566 -226.017328)
		(size 0.4572)
		(drill 0.2032)
		(layers "F.Cu" "B.Cu")
		(net "GND")
	)
	(via
		(at 160.645602 -10.998708)
		(size 0.508)
		(drill 0.254)
		(layers "F.Cu" "B.Cu")
		(net "GND")
	)
	(via
		(at 134.349998 -430.299622)
		(size 0.4572)
		(drill 0.2032)
		(layers "F.Cu" "B.Cu")
		(net "GND")
	)
	(via
		(at 453.121014 -244.916706)
		(size 0.4572)
		(drill 0.2032)
		(layers "F.Cu" "B.Cu")
		(net "GND")
	)
	(via
		(at 120.678194 -264.50036)
		(size 0.4572)
		(drill 0.2032)
		(layers "F.Cu" "B.Cu")
		(net "GND")
	)
	(via
		(at 266.619482 -207.51673)
		(size 0.4572)
		(drill 0.2032)
		(layers "F.Cu" "B.Cu")
		(net "GND")
	)
	(via
		(at 378.84608 -239.853216)
		(size 0.4572)
		(drill 0.2032)
		(layers "F.Cu" "B.Cu")
		(net "GND")
	)
	(via
		(at 26.223214 -312.91657)
		(size 0.4572)
		(drill 0.2032)
		(layers "F.Cu" "B.Cu")
		(net "GND")
	)
	(via
		(at 185.875676 -350.261682)
		(size 0.508)
		(drill 0.254)
		(layers "F.Cu" "B.Cu")
		(net "GND")
	)
	(via
		(at 191.983614 -291.666676)
		(size 0.4572)
		(drill 0.2032)
		(layers "F.Cu" "B.Cu")
		(net "GND")
	)
	(via
		(at 283.916882 -272.966688)
		(size 0.4572)
		(drill 0.2032)
		(layers "F.Cu" "B.Cu")
		(net "GND")
	)
	(via
		(at 425.96689 -12.37488)
		(size 0.508)
		(drill 0.254)
		(layers "F.Cu" "B.Cu")
		(net "GND")
	)
	(via
		(at 395.273022 -406.370536)
		(size 0.4572)
		(drill 0.254)
		(layers "F.Cu" "B.Cu")
		(net "GND")
	)
	(via
		(at 455.011282 -301.01667)
		(size 0.4572)
		(drill 0.2032)
		(layers "F.Cu" "B.Cu")
		(net "GND")
	)
	(via
		(at 370.497862 -261.244842)
		(size 0.4572)
		(drill 0.2032)
		(layers "F.Cu" "B.Cu")
		(net "GND")
	)
	(via
		(at 109.657388 -297.19778)
		(size 0.508)
		(drill 0.254)
		(layers "F.Cu" "B.Cu")
		(net "GND")
	)
	(via
		(at 279.816814 -306.116736)
		(size 0.4572)
		(drill 0.2032)
		(layers "F.Cu" "B.Cu")
		(net "GND")
	)
	(via
		(at 358.17048 -238.225584)
		(size 0.4572)
		(drill 0.2032)
		(layers "F.Cu" "B.Cu")
		(net "GND")
	)
	(via
		(at 181.64048 -103.698548)
		(size 0.508)
		(drill 0.254)
		(layers "F.Cu" "B.Cu")
		(net "GND")
	)
	(via
		(at 61.381386 -409.396184)
		(size 0.4572)
		(drill 0.254)
		(layers "F.Cu" "B.Cu")
		(net "GND")
	)
	(via
		(at 125.847348 -253.919736)
		(size 0.4572)
		(drill 0.2032)
		(layers "F.Cu" "B.Cu")
		(net "GND")
	)
	(via
		(at 125.737366 -239.0394)
		(size 0.4572)
		(drill 0.2032)
		(layers "F.Cu" "B.Cu")
		(net "GND")
	)
	(via
		(at 103.8098 -410.0322)
		(size 0.508)
		(drill 0.254)
		(layers "F.Cu" "B.Cu")
		(net "GND")
	)
	(via
		(at 433.832 -25.176988)
		(size 0.508)
		(drill 0.254)
		(layers "F.Cu" "B.Cu")
		(net "GND")
	)
	(via
		(at 98.482912 -237.411514)
		(size 0.4572)
		(drill 0.2032)
		(layers "F.Cu" "B.Cu")
		(net "GND")
	)
	(via
		(at 342.250014 -431.29962)
		(size 0.4572)
		(drill 0.2032)
		(layers "F.Cu" "B.Cu")
		(net "GND")
	)
	(via
		(at 443.367414 -261.916672)
		(size 0.4572)
		(drill 0.2032)
		(layers "F.Cu" "B.Cu")
		(net "GND")
	)
	(via
		(at 28.433014 -289.966654)
		(size 0.4572)
		(drill 0.2032)
		(layers "F.Cu" "B.Cu")
		(net "GND")
	)
	(via
		(at 109.77753 -331.043026)
		(size 0.508)
		(drill 0.254)
		(layers "F.Cu" "B.Cu")
		(net "GND")
	)
	(via
		(at 43.074082 -17.61236)
		(size 0.508)
		(drill 0.254)
		(layers "F.Cu" "B.Cu")
		(net "GND")
	)
	(via
		(at 92.014294 -283.219906)
		(size 0.4572)
		(drill 0.2032)
		(layers "F.Cu" "B.Cu")
		(net "GND")
	)
	(via
		(at 7.035546 -260.21665)
		(size 0.4572)
		(drill 0.2032)
		(layers "F.Cu" "B.Cu")
		(net "GND")
	)
	(via
		(at 407.858214 -304.416714)
		(size 0.4572)
		(drill 0.2032)
		(layers "F.Cu" "B.Cu")
		(net "GND")
	)
	(via
		(at 266.619482 -213.46668)
		(size 0.4572)
		(drill 0.2032)
		(layers "F.Cu" "B.Cu")
		(net "GND")
	)
	(via
		(at 292.694614 -276.366732)
		(size 0.4572)
		(drill 0.2032)
		(layers "F.Cu" "B.Cu")
		(net "GND")
	)
	(via
		(at 156.258006 -406.370536)
		(size 0.4572)
		(drill 0.254)
		(layers "F.Cu" "B.Cu")
		(net "GND")
	)
	(via
		(at 26.223214 -258.516628)
		(size 0.4572)
		(drill 0.2032)
		(layers "F.Cu" "B.Cu")
		(net "GND")
	)
	(via
		(at 91.074494 -276.708616)
		(size 0.4572)
		(drill 0.2032)
		(layers "F.Cu" "B.Cu")
		(net "GND")
	)
	(via
		(at 352.641662 -274.266914)
		(size 0.4572)
		(drill 0.2032)
		(layers "F.Cu" "B.Cu")
		(net "GND")
	)
	(via
		(at 84.541106 -403.249892)
		(size 0.4572)
		(drill 0.254)
		(layers "F.Cu" "B.Cu")
		(net "GND")
	)
	(via
		(at 95.56623 -54.066948)
		(size 0.508)
		(drill 0.254)
		(layers "F.Cu" "B.Cu")
		(net "GND")
	)
	(via
		(at 134.259066 -337.602322)
		(size 0.508)
		(drill 0.254)
		(layers "F.Cu" "B.Cu")
		(net "GND")
	)
	(via
		(at 428.279814 -285.716726)
		(size 0.4572)
		(drill 0.2032)
		(layers "F.Cu" "B.Cu")
		(net "GND")
	)
	(via
		(at 107.520994 -287.28924)
		(size 0.4572)
		(drill 0.2032)
		(layers "F.Cu" "B.Cu")
		(net "GND")
	)
	(via
		(at 130.493262 -406.370536)
		(size 0.4572)
		(drill 0.254)
		(layers "F.Cu" "B.Cu")
		(net "GND")
	)
	(via
		(at 345.953334 -233.34218)
		(size 0.4572)
		(drill 0.2032)
		(layers "F.Cu" "B.Cu")
		(net "GND")
	)
	(via
		(at 132.895848 -269.38351)
		(size 0.4572)
		(drill 0.2032)
		(layers "F.Cu" "B.Cu")
		(net "GND")
	)
	(via
		(at 296.794682 -280.61666)
		(size 0.4572)
		(drill 0.2032)
		(layers "F.Cu" "B.Cu")
		(net "GND")
	)
	(via
		(at 448.75831 -70.975982)
		(size 0.508)
		(drill 0.254)
		(layers "F.Cu" "B.Cu")
		(net "GND")
	)
	(via
		(at 450.911214 -306.116736)
		(size 0.4572)
		(drill 0.2032)
		(layers "F.Cu" "B.Cu")
		(net "GND")
	)
	(via
		(at 368.148616 -283.219906)
		(size 0.4572)
		(drill 0.2032)
		(layers "F.Cu" "B.Cu")
		(net "GND")
	)
	(via
		(at 201.737214 -262.76681)
		(size 0.4572)
		(drill 0.2032)
		(layers "F.Cu" "B.Cu")
		(net "GND")
	)
	(via
		(at 126.316994 -279.150318)
		(size 0.4572)
		(drill 0.2032)
		(layers "F.Cu" "B.Cu")
		(net "GND")
	)
	(via
		(at 37.688266 -18.246344)
		(size 0.508)
		(drill 0.254)
		(layers "F.Cu" "B.Cu")
		(net "GND")
	)
	(via
		(at 295.587928 -52.041298)
		(size 0.508)
		(drill 0.254)
		(layers "F.Cu" "B.Cu")
		(net "GND")
	)
	(via
		(at 195.427346 -208.366614)
		(size 0.4572)
		(drill 0.2032)
		(layers "F.Cu" "B.Cu")
		(net "GND")
	)
	(via
		(at 59.842146 -201.56678)
		(size 0.4572)
		(drill 0.2032)
		(layers "F.Cu" "B.Cu")
		(net "GND")
	)
	(via
		(at 349.822262 -280.778204)
		(size 0.4572)
		(drill 0.2032)
		(layers "F.Cu" "B.Cu")
		(net "GND")
	)
	(via
		(at 9.245346 -281.466798)
		(size 0.4572)
		(drill 0.2032)
		(layers "F.Cu" "B.Cu")
		(net "GND")
	)
	(via
		(at 100.832666 -241.481102)
		(size 0.4572)
		(drill 0.2032)
		(layers "F.Cu" "B.Cu")
		(net "GND")
	)
	(via
		(at 374.14708 -231.714548)
		(size 0.4572)
		(drill 0.2032)
		(layers "F.Cu" "B.Cu")
		(net "GND")
	)
	(via
		(at 345.483434 -226.017328)
		(size 0.4572)
		(drill 0.2032)
		(layers "F.Cu" "B.Cu")
		(net "GND")
	)
	(via
		(at 20.924266 -18.246344)
		(size 0.508)
		(drill 0.254)
		(layers "F.Cu" "B.Cu")
		(net "GND")
	)
	(via
		(at 378.956062 -266.128246)
		(size 0.4572)
		(drill 0.2032)
		(layers "F.Cu" "B.Cu")
		(net "GND")
	)
	(via
		(at 386.350002 -425.547282)
		(size 0.4572)
		(drill 0.2032)
		(layers "F.Cu" "B.Cu")
		(net "GND")
	)
	(via
		(at 420.736014 -234.716574)
		(size 0.4572)
		(drill 0.2032)
		(layers "F.Cu" "B.Cu")
		(net "GND")
	)
	(via
		(at 48.92548 -345.642438)
		(size 0.508)
		(drill 0.254)
		(layers "F.Cu" "B.Cu")
		(net "GND")
	)
	(via
		(at 431.326798 -182.45963)
		(size 0.508)
		(drill 0.254)
		(layers "F.Cu" "B.Cu")
		(net "GND")
	)
	(via
		(at 56.51373 -409.396184)
		(size 0.4572)
		(drill 0.254)
		(layers "F.Cu" "B.Cu")
		(net "GND")
	)
	(via
		(at 187.883546 -298.466764)
		(size 0.4572)
		(drill 0.2032)
		(layers "F.Cu" "B.Cu")
		(net "GND")
	)
	(via
		(at 195.427346 -263.616694)
		(size 0.4572)
		(drill 0.2032)
		(layers "F.Cu" "B.Cu")
		(net "GND")
	)
	(via
		(at 431.092356 -110.14837)
		(size 0.508)
		(drill 0.254)
		(layers "F.Cu" "B.Cu")
		(net "GND")
	)
	(via
		(at 52.298346 -216.016586)
		(size 0.4572)
		(drill 0.2032)
		(layers "F.Cu" "B.Cu")
		(net "GND")
	)
	(via
		(at 119.97309 -335.704434)
		(size 0.49022)
		(drill 0.254)
		(layers "F.Cu" "B.Cu")
		(net "GND")
	)
	(via
		(at 71.250048 -431.451258)
		(size 0.4572)
		(drill 0.2032)
		(layers "F.Cu" "B.Cu")
		(net "GND")
	)
	(via
		(at 413.192214 -304.416714)
		(size 0.4572)
		(drill 0.2032)
		(layers "F.Cu" "B.Cu")
		(net "GND")
	)
	(via
		(at 450.88556 -58.875168)
		(size 0.508)
		(drill 0.254)
		(layers "F.Cu" "B.Cu")
		(net "GND")
	)
	(via
		(at 423.0878 -148.199348)
		(size 0.508)
		(drill 0.254)
		(layers "F.Cu" "B.Cu")
		(net "GND")
	)
	(via
		(at 346.893134 -220.319854)
		(size 0.4572)
		(drill 0.2032)
		(layers "F.Cu" "B.Cu")
		(net "GND")
	)
	(via
		(at 444.39713 -70.284594)
		(size 0.508)
		(drill 0.254)
		(layers "F.Cu" "B.Cu")
		(net "GND")
	)
	(via
		(at 384.594862 -277.522432)
		(size 0.4572)
		(drill 0.2032)
		(layers "F.Cu" "B.Cu")
		(net "GND")
	)
	(via
		(at 245.54688 -129.885948)
		(size 0.508)
		(drill 0.254)
		(layers "F.Cu" "B.Cu")
		(net "GND")
	)
	(via
		(at 132.315966 -219.506038)
		(size 0.4572)
		(drill 0.2032)
		(layers "F.Cu" "B.Cu")
		(net "GND")
	)
	(via
		(at 143.34998 -427.851316)
		(size 0.4572)
		(drill 0.2032)
		(layers "F.Cu" "B.Cu")
		(net "GND")
	)
	(via
		(at 422.945814 -276.366732)
		(size 0.4572)
		(drill 0.2032)
		(layers "F.Cu" "B.Cu")
		(net "GND")
	)
	(via
		(at 352.531934 -213.732618)
		(size 0.4572)
		(drill 0.2032)
		(layers "F.Cu" "B.Cu")
		(net "GND")
	)
	(via
		(at 446.677542 -21.236178)
		(size 0.508)
		(drill 0.254)
		(layers "F.Cu" "B.Cu")
		(net "GND")
	)
	(via
		(at 332.144624 -338.964016)
		(size 0.508)
		(drill 0.254)
		(layers "F.Cu" "B.Cu")
		(net "GND")
	)
	(via
		(at 430.489614 -240.666778)
		(size 0.4572)
		(drill 0.2032)
		(layers "F.Cu" "B.Cu")
		(net "GND")
	)
	(via
		(at 171.562014 -282.316682)
		(size 0.4572)
		(drill 0.2032)
		(layers "F.Cu" "B.Cu")
		(net "GND")
	)
	(via
		(at 261.285482 -299.316648)
		(size 0.4572)
		(drill 0.2032)
		(layers "F.Cu" "B.Cu")
		(net "GND")
	)
	(via
		(at 313.957208 -407.00452)
		(size 0.4064)
		(drill 0.2032)
		(layers "F.Cu" "B.Cu")
		(net "GND")
	)
	(via
		(at 442.133482 -267.866622)
		(size 0.4572)
		(drill 0.2032)
		(layers "F.Cu" "B.Cu")
		(net "GND")
	)
	(via
		(at 291.460682 -198.166736)
		(size 0.4572)
		(drill 0.2032)
		(layers "F.Cu" "B.Cu")
		(net "GND")
	)
	(via
		(at 151.349964 -425.547282)
		(size 0.4572)
		(drill 0.2032)
		(layers "F.Cu" "B.Cu")
		(net "GND")
	)
	(via
		(at 132.425694 -257.175254)
		(size 0.4572)
		(drill 0.2032)
		(layers "F.Cu" "B.Cu")
		(net "GND")
	)
	(via
		(at 31.07309 -19.13636)
		(size 0.508)
		(drill 0.254)
		(layers "F.Cu" "B.Cu")
		(net "GND")
	)
	(via
		(at 430.577752 -319.294256)
		(size 0.4572)
		(drill 0.2032)
		(layers "F.Cu" "B.Cu")
		(net "GND")
	)
	(via
		(at 375.557034 -240.667286)
		(size 0.4572)
		(drill 0.2032)
		(layers "F.Cu" "B.Cu")
		(net "GND")
	)
	(via
		(at 143.020034 -403.883876)
		(size 0.4064)
		(drill 0.2032)
		(layers "F.Cu" "B.Cu")
		(net "GND")
	)
	(via
		(at 42.554906 -19.13636)
		(size 0.508)
		(drill 0.254)
		(layers "F.Cu" "B.Cu")
		(net "GND")
	)
	(via
		(at 358.170734 -236.597952)
		(size 0.4572)
		(drill 0.2032)
		(layers "F.Cu" "B.Cu")
		(net "GND")
	)
	(via
		(at 356.62616 -331.08392)
		(size 0.508)
		(drill 0.254)
		(layers "F.Cu" "B.Cu")
		(net "GND")
	)
	(via
		(at 191.983614 -282.316682)
		(size 0.4572)
		(drill 0.2032)
		(layers "F.Cu" "B.Cu")
		(net "GND")
	)
	(via
		(at 420.736014 -210.916774)
		(size 0.4572)
		(drill 0.2032)
		(layers "F.Cu" "B.Cu")
		(net "GND")
	)
	(via
		(at 44.754546 -238.966756)
		(size 0.4572)
		(drill 0.2032)
		(layers "F.Cu" "B.Cu")
		(net "GND")
	)
	(via
		(at 449.677282 -216.866724)
		(size 0.4572)
		(drill 0.2032)
		(layers "F.Cu" "B.Cu")
		(net "GND")
	)
	(via
		(at 56.182514 -219.41663)
		(size 0.4572)
		(drill 0.2032)
		(layers "F.Cu" "B.Cu")
		(net "GND")
	)
	(via
		(at 400.053302 -400.224244)
		(size 0.4572)
		(drill 0.254)
		(layers "F.Cu" "B.Cu")
		(net "GND")
	)
	(via
		(at 319.25006 -432.747166)
		(size 0.4572)
		(drill 0.2032)
		(layers "F.Cu" "B.Cu")
		(net "GND")
	)
	(via
		(at 386.083302 -407.638504)
		(size 0.4572)
		(drill 0.254)
		(layers "F.Cu" "B.Cu")
		(net "GND")
	)
	(via
		(at 129.136394 -269.38351)
		(size 0.4572)
		(drill 0.2032)
		(layers "F.Cu" "B.Cu")
		(net "GND")
	)
	(via
		(at 117.964458 -329.22972)
		(size 0.508)
		(drill 0.254)
		(layers "F.Cu" "B.Cu")
		(net "GND")
	)
	(via
		(at 171.562014 -308.666642)
		(size 0.4572)
		(drill 0.2032)
		(layers "F.Cu" "B.Cu")
		(net "GND")
	)
	(via
		(at 130.906012 -241.481102)
		(size 0.4572)
		(drill 0.2032)
		(layers "F.Cu" "B.Cu")
		(net "GND")
	)
	(via
		(at 430.489614 -216.016586)
		(size 0.4572)
		(drill 0.2032)
		(layers "F.Cu" "B.Cu")
		(net "GND")
	)
	(via
		(at 434.082952 -386.321554)
		(size 0.508)
		(drill 0.254)
		(layers "F.Cu" "B.Cu")
		(net "GND")
	)
	(via
		(at 306.764182 -219.41663)
		(size 0.4572)
		(drill 0.2032)
		(layers "F.Cu" "B.Cu")
		(net "GND")
	)
	(via
		(at 91.544394 -256.361438)
		(size 0.4572)
		(drill 0.2032)
		(layers "F.Cu" "B.Cu")
		(net "GND")
	)
	(via
		(at 343.13368 -249.620024)
		(size 0.4572)
		(drill 0.2032)
		(layers "F.Cu" "B.Cu")
		(net "GND")
	)
	(via
		(at 46.964346 -204.96657)
		(size 0.4572)
		(drill 0.2032)
		(layers "F.Cu" "B.Cu")
		(net "GND")
	)
	(via
		(at 123.96978 -109.070648)
		(size 0.508)
		(drill 0.254)
		(layers "F.Cu" "B.Cu")
		(net "GND")
	)
	(via
		(at 23.59533 -441.225432)
		(size 0.508)
		(drill 0.254)
		(layers "F.Cu" "B.Cu")
		(net "GND")
	)
	(via
		(at 122.448066 -239.853216)
		(size 0.4572)
		(drill 0.2032)
		(layers "F.Cu" "B.Cu")
		(net "GND")
	)
	(via
		(at 417.292282 -213.46668)
		(size 0.4572)
		(drill 0.2032)
		(layers "F.Cu" "B.Cu")
		(net "GND")
	)
	(via
		(at 41.310814 -213.46668)
		(size 0.4572)
		(drill 0.2032)
		(layers "F.Cu" "B.Cu")
		(net "GND")
	)
	(via
		(at 169.352214 -204.116686)
		(size 0.4572)
		(drill 0.2032)
		(layers "F.Cu" "B.Cu")
		(net "GND")
	)
	(via
		(at 216.824814 -226.216718)
		(size 0.4572)
		(drill 0.2032)
		(layers "F.Cu" "B.Cu")
		(net "GND")
	)
	(via
		(at 272.273014 -246.616728)
		(size 0.4572)
		(drill 0.2032)
		(layers "F.Cu" "B.Cu")
		(net "GND")
	)
	(via
		(at 376.966734 -246.364506)
		(size 0.4572)
		(drill 0.2032)
		(layers "F.Cu" "B.Cu")
		(net "GND")
	)
	(via
		(at 427.045882 -213.46668)
		(size 0.4572)
		(drill 0.2032)
		(layers "F.Cu" "B.Cu")
		(net "GND")
	)
	(via
		(at 184.439814 -282.316682)
		(size 0.4572)
		(drill 0.2032)
		(layers "F.Cu" "B.Cu")
		(net "GND")
	)
	(via
		(at 157.349952 -436.051198)
		(size 0.4572)
		(drill 0.2032)
		(layers "F.Cu" "B.Cu")
		(net "GND")
	)
	(via
		(at 311.882282 -198.166736)
		(size 0.4572)
		(drill 0.2032)
		(layers "F.Cu" "B.Cu")
		(net "GND")
	)
	(via
		(at 169.123614 -272.966688)
		(size 0.4572)
		(drill 0.2032)
		(layers "F.Cu" "B.Cu")
		(net "GND")
	)
	(via
		(at 41.310814 -228.766624)
		(size 0.4572)
		(drill 0.2032)
		(layers "F.Cu" "B.Cu")
		(net "GND")
	)
	(via
		(at 393.714478 -176.14519)
		(size 0.508)
		(drill 0.254)
		(layers "F.Cu" "B.Cu")
		(net "GND")
	)
	(via
		(at 346.045028 -326.910192)
		(size 0.508)
		(drill 0.254)
		(layers "F.Cu" "B.Cu")
		(net "GND")
	)
	(via
		(at 55.16753 -401.492212)
		(size 0.4572)
		(drill 0.254)
		(layers "F.Cu" "B.Cu")
		(net "GND")
	)
	(via
		(at 178.289204 -46.800008)
		(size 0.508)
		(drill 0.254)
		(layers "F.Cu" "B.Cu")
		(net "GND")
	)
	(via
		(at 175.005746 -313.766708)
		(size 0.4572)
		(drill 0.2032)
		(layers "F.Cu" "B.Cu")
		(net "GND")
	)
	(via
		(at 420.736014 -221.96679)
		(size 0.4572)
		(drill 0.2032)
		(layers "F.Cu" "B.Cu")
		(net "GND")
	)
	(via
		(at 464.764882 -211.766658)
		(size 0.4572)
		(drill 0.2032)
		(layers "F.Cu" "B.Cu")
		(net "GND")
	)
	(via
		(at 39.420546 -197.316598)
		(size 0.4572)
		(drill 0.2032)
		(layers "F.Cu" "B.Cu")
		(net "GND")
	)
	(via
		(at 95.56623 -55.209948)
		(size 0.508)
		(drill 0.254)
		(layers "F.Cu" "B.Cu")
		(net "GND")
	)
	(via
		(at 347.473016 -263.686544)
		(size 0.4572)
		(drill 0.2032)
		(layers "F.Cu" "B.Cu")
		(net "GND")
	)
	(via
		(at 115.716304 -361.72775)
		(size 0.508)
		(drill 0.254)
		(layers "F.Cu" "B.Cu")
		(net "GND")
	)
	(via
		(at 413.192214 -248.31675)
		(size 0.4572)
		(drill 0.2032)
		(layers "F.Cu" "B.Cu")
		(net "GND")
	)
	(via
		(at 432.379882 -222.816674)
		(size 0.4572)
		(drill 0.2032)
		(layers "F.Cu" "B.Cu")
		(net "GND")
	)
	(via
		(at 445.577214 -204.96657)
		(size 0.4572)
		(drill 0.2032)
		(layers "F.Cu" "B.Cu")
		(net "GND")
	)
	(via
		(at 354.490274 -176.557432)
		(size 0.508)
		(drill 0.254)
		(layers "F.Cu" "B.Cu")
		(net "GND")
	)
	(via
		(at 290.144708 -93.099128)
		(size 0.508)
		(drill 0.254)
		(layers "F.Cu" "B.Cu")
		(net "GND")
	)
	(via
		(at 427.43374 -118.34876)
		(size 0.508)
		(drill 0.254)
		(layers "F.Cu" "B.Cu")
		(net "GND")
	)
	(via
		(at 213.6902 -113.4872)
		(size 0.508)
		(drill 0.254)
		(layers "F.Cu" "B.Cu")
		(net "GND")
	)
	(via
		(at 158.062422 -406.370536)
		(size 0.4572)
		(drill 0.254)
		(layers "F.Cu" "B.Cu")
		(net "GND")
	)
	(via
		(at 457.221082 -306.96662)
		(size 0.4572)
		(drill 0.2032)
		(layers "F.Cu" "B.Cu")
		(net "GND")
	)
	(via
		(at 279.794716 -319.303908)
		(size 0.4572)
		(drill 0.2032)
		(layers "F.Cu" "B.Cu")
		(net "GND")
	)
	(via
		(at 130.906012 -234.970066)
		(size 0.4572)
		(drill 0.2032)
		(layers "F.Cu" "B.Cu")
		(net "GND")
	)
	(via
		(at 332.32598 -242.294918)
		(size 0.4572)
		(drill 0.2032)
		(layers "F.Cu" "B.Cu")
		(net "GND")
	)
	(via
		(at 435.823614 -240.666778)
		(size 0.4572)
		(drill 0.2032)
		(layers "F.Cu" "B.Cu")
		(net "GND")
	)
	(via
		(at 155.349956 -433.899564)
		(size 0.4572)
		(drill 0.2032)
		(layers "F.Cu" "B.Cu")
		(net "GND")
	)
	(via
		(at 433.166774 -7.215124)
		(size 0.508)
		(drill 0.254)
		(layers "F.Cu" "B.Cu")
		(net "GND")
	)
	(via
		(at 179.105814 -219.41663)
		(size 0.4572)
		(drill 0.2032)
		(layers "F.Cu" "B.Cu")
		(net "GND")
	)
	(via
		(at 172.795946 -315.46673)
		(size 0.4572)
		(drill 0.2032)
		(layers "F.Cu" "B.Cu")
		(net "GND")
	)
	(via
		(at 383.020062 -410.664152)
		(size 0.4572)
		(drill 0.254)
		(layers "F.Cu" "B.Cu")
		(net "GND")
	)
	(via
		(at 432.379882 -286.56661)
		(size 0.4572)
		(drill 0.2032)
		(layers "F.Cu" "B.Cu")
		(net "GND")
	)
	(via
		(at 26.223214 -194.766692)
		(size 0.4572)
		(drill 0.2032)
		(layers "F.Cu" "B.Cu")
		(net "GND")
	)
	(via
		(at 404.55977 -403.883876)
		(size 0.4064)
		(drill 0.2032)
		(layers "F.Cu" "B.Cu")
		(net "GND")
	)
	(via
		(at 60.035186 -400.224244)
		(size 0.4572)
		(drill 0.254)
		(layers "F.Cu" "B.Cu")
		(net "GND")
	)
	(via
		(at 357.560626 -338.47024)
		(size 0.508)
		(drill 0.254)
		(layers "F.Cu" "B.Cu")
		(net "GND")
	)
	(via
		(at 2.764536 -264.590022)
		(size 0.508)
		(drill 0.254)
		(layers "F.Cu" "B.Cu")
		(net "GND")
	)
	(via
		(at 399.349976 -425.547282)
		(size 0.4572)
		(drill 0.2032)
		(layers "F.Cu" "B.Cu")
		(net "GND")
	)
	(via
		(at 328.323956 -200.63714)
		(size 0.508)
		(drill 0.254)
		(layers "F.Cu" "B.Cu")
		(net "GND")
	)
	(via
		(at 108.025946 -330.42352)
		(size 0.508)
		(drill 0.254)
		(layers "F.Cu" "B.Cu")
		(net "GND")
	)
	(via
		(at 398.446752 -10.16508)
		(size 0.508)
		(drill 0.254)
		(layers "F.Cu" "B.Cu")
		(net "GND")
	)
	(via
		(at 18.679414 -301.01667)
		(size 0.4572)
		(drill 0.2032)
		(layers "F.Cu" "B.Cu")
		(net "GND")
	)
	(via
		(at 428.272448 -19.125438)
		(size 0.508)
		(drill 0.254)
		(layers "F.Cu" "B.Cu")
		(net "GND")
	)
	(via
		(at 307.830728 -410.030168)
		(size 0.4064)
		(drill 0.2032)
		(layers "F.Cu" "B.Cu")
		(net "GND")
	)
	(via
		(at 348.882462 -264.50036)
		(size 0.4572)
		(drill 0.2032)
		(layers "F.Cu" "B.Cu")
		(net "GND")
	)
	(via
		(at 113.62944 -263.686544)
		(size 0.4572)
		(drill 0.2032)
		(layers "F.Cu" "B.Cu")
		(net "GND")
	)
	(via
		(at 44.754546 -250.016772)
		(size 0.4572)
		(drill 0.2032)
		(layers "F.Cu" "B.Cu")
		(net "GND")
	)
	(via
		(at 310.207914 -273.816572)
		(size 0.4572)
		(drill 0.2032)
		(layers "F.Cu" "B.Cu")
		(net "GND")
	)
	(via
		(at 331.880718 -50.799746)
		(size 0.4572)
		(drill 0.2032)
		(layers "F.Cu" "B.Cu")
		(net "GND")
	)
	(via
		(at 443.367414 -263.616694)
		(size 0.4572)
		(drill 0.2032)
		(layers "F.Cu" "B.Cu")
		(net "GND")
	)
	(via
		(at 341.724234 -237.411514)
		(size 0.4572)
		(drill 0.2032)
		(layers "F.Cu" "B.Cu")
		(net "GND")
	)
	(via
		(at 116.127784 -292.95598)
		(size 0.508)
		(drill 0.254)
		(layers "F.Cu" "B.Cu")
		(net "GND")
	)
	(via
		(at 59.842146 -278.066754)
		(size 0.4572)
		(drill 0.2032)
		(layers "F.Cu" "B.Cu")
		(net "GND")
	)
	(via
		(at 169.352214 -233.86669)
		(size 0.4572)
		(drill 0.2032)
		(layers "F.Cu" "B.Cu")
		(net "GND")
	)
	(via
		(at 112.110266 -223.575626)
		(size 0.4572)
		(drill 0.2032)
		(layers "F.Cu" "B.Cu")
		(net "GND")
	)
	(via
		(at 24.332946 -317.166752)
		(size 0.4572)
		(drill 0.2032)
		(layers "F.Cu" "B.Cu")
		(net "GND")
	)
	(via
		(at 280.810462 -90.54465)
		(size 0.508)
		(drill 0.254)
		(layers "F.Cu" "B.Cu")
		(net "GND")
	)
	(via
		(at 9.245346 -279.766776)
		(size 0.4572)
		(drill 0.2032)
		(layers "F.Cu" "B.Cu")
		(net "GND")
	)
	(via
		(at 420.736014 -220.266768)
		(size 0.4572)
		(drill 0.2032)
		(layers "F.Cu" "B.Cu")
		(net "GND")
	)
	(via
		(at 180.339746 -231.316784)
		(size 0.4572)
		(drill 0.2032)
		(layers "F.Cu" "B.Cu")
		(net "GND")
	)
	(via
		(at 259.075682 -211.766658)
		(size 0.4572)
		(drill 0.2032)
		(layers "F.Cu" "B.Cu")
		(net "GND")
	)
	(via
		(at 371.797834 -222.761556)
		(size 0.4572)
		(drill 0.2032)
		(layers "F.Cu" "B.Cu")
		(net "GND")
	)
	(via
		(at 344.543634 -222.761556)
		(size 0.4572)
		(drill 0.2032)
		(layers "F.Cu" "B.Cu")
		(net "GND")
	)
	(via
		(at 95.631 -92.134944)
		(size 0.508)
		(drill 0.254)
		(layers "F.Cu" "B.Cu")
		(net "GND")
	)
	(via
		(at 110.340394 -287.28924)
		(size 0.4572)
		(drill 0.2032)
		(layers "F.Cu" "B.Cu")
		(net "GND")
	)
	(via
		(at 417.98875 -153.23693)
		(size 0.508)
		(drill 0.254)
		(layers "F.Cu" "B.Cu")
		(net "GND")
	)
	(via
		(at 418.342064 -361.734862)
		(size 0.49022)
		(drill 0.254)
		(layers "F.Cu" "B.Cu")
		(net "GND")
	)
	(via
		(at 20.889214 -224.516696)
		(size 0.4572)
		(drill 0.2032)
		(layers "F.Cu" "B.Cu")
		(net "GND")
	)
	(via
		(at 413.192214 -278.066754)
		(size 0.4572)
		(drill 0.2032)
		(layers "F.Cu" "B.Cu")
		(net "GND")
	)
	(via
		(at 48.854614 -301.01667)
		(size 0.4572)
		(drill 0.2032)
		(layers "F.Cu" "B.Cu")
		(net "GND")
	)
	(via
		(at 29.306266 -18.502376)
		(size 0.508)
		(drill 0.254)
		(layers "F.Cu" "B.Cu")
		(net "GND")
	)
	(via
		(at 105.45699 -257.69316)
		(size 0.4572)
		(drill 0.2032)
		(layers "F.Cu" "B.Cu")
		(net "GND")
	)
	(via
		(at 160.121346 -283.166566)
		(size 0.4572)
		(drill 0.2032)
		(layers "F.Cu" "B.Cu")
		(net "GND")
	)
	(via
		(at 351.468436 -61.805566)
		(size 0.508)
		(drill 0.254)
		(layers "F.Cu" "B.Cu")
		(net "GND")
	)
	(via
		(at 149.349968 -426.54728)
		(size 0.4572)
		(drill 0.2032)
		(layers "F.Cu" "B.Cu")
		(net "GND")
	)
	(via
		(at 47.62246 -144.463008)
		(size 0.508)
		(drill 0.254)
		(layers "F.Cu" "B.Cu")
		(net "GND")
	)
	(via
		(at 279.816814 -276.366732)
		(size 0.4572)
		(drill 0.2032)
		(layers "F.Cu" "B.Cu")
		(net "GND")
	)
	(via
		(at 294.82288 -45.938948)
		(size 0.508)
		(drill 0.254)
		(layers "F.Cu" "B.Cu")
		(net "GND")
	)
	(via
		(at 365.888778 -331.57922)
		(size 0.508)
		(drill 0.254)
		(layers "F.Cu" "B.Cu")
		(net "GND")
	)
	(via
		(at 320.444876 -410.664152)
		(size 0.4572)
		(drill 0.254)
		(layers "F.Cu" "B.Cu")
		(net "GND")
	)
	(via
		(at 174.43704 -56.619648)
		(size 0.508)
		(drill 0.254)
		(layers "F.Cu" "B.Cu")
		(net "GND")
	)
	(via
		(at 111.640366 -214.546434)
		(size 0.4572)
		(drill 0.2032)
		(layers "F.Cu" "B.Cu")
		(net "GND")
	)
	(via
		(at 153.34996 -437.34736)
		(size 0.4572)
		(drill 0.2032)
		(layers "F.Cu" "B.Cu")
		(net "GND")
	)
	(via
		(at 438.033414 -246.616728)
		(size 0.4572)
		(drill 0.2032)
		(layers "F.Cu" "B.Cu")
		(net "GND")
	)
	(via
		(at 75.351386 -401.492212)
		(size 0.4572)
		(drill 0.254)
		(layers "F.Cu" "B.Cu")
		(net "GND")
	)
	(via
		(at 171.562014 -245.76659)
		(size 0.4572)
		(drill 0.2032)
		(layers "F.Cu" "B.Cu")
		(net "GND")
	)
	(via
		(at 55.260494 -147.200874)
		(size 0.49022)
		(drill 0.254)
		(layers "F.Cu" "B.Cu")
		(net "GND")
	)
	(via
		(at 415.648648 -179.438554)
		(size 0.49022)
		(drill 0.254)
		(layers "F.Cu" "B.Cu")
		(net "GND")
	)
	(via
		(at 87.604346 -400.224244)
		(size 0.4572)
		(drill 0.254)
		(layers "F.Cu" "B.Cu")
		(net "GND")
	)
	(via
		(at 285.150814 -301.866808)
		(size 0.4572)
		(drill 0.2032)
		(layers "F.Cu" "B.Cu")
		(net "GND")
	)
	(via
		(at 35.976814 -306.96662)
		(size 0.4572)
		(drill 0.2032)
		(layers "F.Cu" "B.Cu")
		(net "GND")
	)
	(via
		(at 431.623978 -183.50611)
		(size 0.508)
		(drill 0.254)
		(layers "F.Cu" "B.Cu")
		(net "GND")
	)
	(via
		(at 442.133482 -221.116652)
		(size 0.4572)
		(drill 0.2032)
		(layers "F.Cu" "B.Cu")
		(net "GND")
	)
	(via
		(at 97.543366 -234.15625)
		(size 0.4572)
		(drill 0.2032)
		(layers "F.Cu" "B.Cu")
		(net "GND")
	)
	(via
		(at 43.85691 -12.37488)
		(size 0.508)
		(drill 0.254)
		(layers "F.Cu" "B.Cu")
		(net "GND")
	)
	(via
		(at 126.350014 -425.547282)
		(size 0.4572)
		(drill 0.2032)
		(layers "F.Cu" "B.Cu")
		(net "GND")
	)
	(via
		(at 345.593416 -263.686544)
		(size 0.4572)
		(drill 0.2032)
		(layers "F.Cu" "B.Cu")
		(net "GND")
	)
	(via
		(at 259.075682 -224.516696)
		(size 0.4572)
		(drill 0.2032)
		(layers "F.Cu" "B.Cu")
		(net "GND")
	)
	(via
		(at 130.906266 -220.319854)
		(size 0.4572)
		(drill 0.2032)
		(layers "F.Cu" "B.Cu")
		(net "GND")
	)
	(via
		(at 37.210746 -281.466798)
		(size 0.4572)
		(drill 0.2032)
		(layers "F.Cu" "B.Cu")
		(net "GND")
	)
	(via
		(at 210.514946 -195.616576)
		(size 0.4572)
		(drill 0.2032)
		(layers "F.Cu" "B.Cu")
		(net "GND")
	)
	(via
		(at 22.123146 -197.316598)
		(size 0.4572)
		(drill 0.2032)
		(layers "F.Cu" "B.Cu")
		(net "GND")
	)
	(via
		(at 14.579346 -272.116804)
		(size 0.4572)
		(drill 0.2032)
		(layers "F.Cu" "B.Cu")
		(net "GND")
	)
	(via
		(at 159.918146 -278.066754)
		(size 0.4572)
		(drill 0.2032)
		(layers "F.Cu" "B.Cu")
		(net "GND")
	)
	(via
		(at 62.051946 -195.616576)
		(size 0.4572)
		(drill 0.2032)
		(layers "F.Cu" "B.Cu")
		(net "GND")
	)
	(via
		(at 414.808162 -360.148378)
		(size 0.49022)
		(drill 0.254)
		(layers "F.Cu" "B.Cu")
		(net "GND")
	)
	(via
		(at 55.16753 -400.224244)
		(size 0.4572)
		(drill 0.254)
		(layers "F.Cu" "B.Cu")
		(net "GND")
	)
	(via
		(at 127.147066 -223.575626)
		(size 0.4572)
		(drill 0.2032)
		(layers "F.Cu" "B.Cu")
		(net "GND")
	)
	(via
		(at 134.305548 -258.80314)
		(size 0.4572)
		(drill 0.2032)
		(layers "F.Cu" "B.Cu")
		(net "GND")
	)
	(via
		(at 112.484662 -137.799826)
		(size 0.508)
		(drill 0.254)
		(layers "F.Cu" "B.Cu")
		(net "GND")
	)
	(via
		(at 186.649614 -249.166634)
		(size 0.4572)
		(drill 0.2032)
		(layers "F.Cu" "B.Cu")
		(net "GND")
	)
	(via
		(at 149.349968 -439.651394)
		(size 0.4572)
		(drill 0.2032)
		(layers "F.Cu" "B.Cu")
		(net "GND")
	)
	(via
		(at 136.654794 -282.405836)
		(size 0.4572)
		(drill 0.2032)
		(layers "F.Cu" "B.Cu")
		(net "GND")
	)
	(via
		(at 424.181016 -134.89051)
		(size 0.508)
		(drill 0.254)
		(layers "F.Cu" "B.Cu")
		(net "GND")
	)
	(via
		(at 216.824814 -314.616592)
		(size 0.4572)
		(drill 0.2032)
		(layers "F.Cu" "B.Cu")
		(net "GND")
	)
	(via
		(at 89.085166 -219.506038)
		(size 0.4572)
		(drill 0.2032)
		(layers "F.Cu" "B.Cu")
		(net "GND")
	)
	(via
		(at 99.339654 -96.758506)
		(size 0.508)
		(drill 0.254)
		(layers "F.Cu" "B.Cu")
		(net "GND")
	)
	(via
		(at 210.514946 -287.416748)
		(size 0.4572)
		(drill 0.2032)
		(layers "F.Cu" "B.Cu")
		(net "GND")
	)
	(via
		(at 26.223214 -200.716642)
		(size 0.4572)
		(drill 0.2032)
		(layers "F.Cu" "B.Cu")
		(net "GND")
	)
	(via
		(at 352.062034 -222.761556)
		(size 0.4572)
		(drill 0.2032)
		(layers "F.Cu" "B.Cu")
		(net "GND")
	)
	(via
		(at 56.049672 -164.422074)
		(size 0.49022)
		(drill 0.254)
		(layers "F.Cu" "B.Cu")
		(net "GND")
	)
	(via
		(at 382.245616 -262.058658)
		(size 0.4572)
		(drill 0.2032)
		(layers "F.Cu" "B.Cu")
		(net "GND")
	)
	(via
		(at 336.195162 -258.80314)
		(size 0.4572)
		(drill 0.2032)
		(layers "F.Cu" "B.Cu")
		(net "GND")
	)
	(via
		(at 414.756854 -10.16508)
		(size 0.508)
		(drill 0.254)
		(layers "F.Cu" "B.Cu")
		(net "GND")
	)
	(via
		(at 77.90688 -10.155428)
		(size 0.508)
		(drill 0.254)
		(layers "F.Cu" "B.Cu")
		(net "GND")
	)
	(via
		(at 7.035546 -244.916706)
		(size 0.4572)
		(drill 0.2032)
		(layers "F.Cu" "B.Cu")
		(net "GND")
	)
	(via
		(at 384.124962 -279.964134)
		(size 0.4572)
		(drill 0.2032)
		(layers "F.Cu" "B.Cu")
		(net "GND")
	)
	(via
		(at 276.373082 -198.166736)
		(size 0.4572)
		(drill 0.2032)
		(layers "F.Cu" "B.Cu")
		(net "GND")
	)
	(via
		(at 175.005746 -279.766776)
		(size 0.4572)
		(drill 0.2032)
		(layers "F.Cu" "B.Cu")
		(net "GND")
	)
	(via
		(at 201.737214 -232.166668)
		(size 0.4572)
		(drill 0.2032)
		(layers "F.Cu" "B.Cu")
		(net "GND")
	)
	(via
		(at 124.437394 -259.616956)
		(size 0.4572)
		(drill 0.2032)
		(layers "F.Cu" "B.Cu")
		(net "GND")
	)
	(via
		(at 0.76454 -31.320232)
		(size 0.508)
		(drill 0.254)
		(layers "F.Cu" "B.Cu")
		(net "GND")
	)
	(via
		(at 129.026666 -220.319854)
		(size 0.4572)
		(drill 0.2032)
		(layers "F.Cu" "B.Cu")
		(net "GND")
	)
	(via
		(at 306.484528 -400.858228)
		(size 0.4064)
		(drill 0.2032)
		(layers "F.Cu" "B.Cu")
		(net "GND")
	)
	(via
		(at 454.803002 -69.461634)
		(size 0.508)
		(drill 0.254)
		(layers "F.Cu" "B.Cu")
		(net "GND")
	)
	(via
		(at 154.900376 -83.923378)
		(size 0.508)
		(drill 0.254)
		(layers "F.Cu" "B.Cu")
		(net "GND")
	)
	(via
		(at 137.594594 -280.778204)
		(size 0.4572)
		(drill 0.2032)
		(layers "F.Cu" "B.Cu")
		(net "GND")
	)
	(via
		(at 160.764474 -407.00452)
		(size 0.4064)
		(drill 0.2032)
		(layers "F.Cu" "B.Cu")
		(net "GND")
	)
	(via
		(at 266.619482 -222.816674)
		(size 0.4572)
		(drill 0.2032)
		(layers "F.Cu" "B.Cu")
		(net "GND")
	)
	(via
		(at 150.79345 -135.814308)
		(size 0.508)
		(drill 0.254)
		(layers "F.Cu" "B.Cu")
		(net "GND")
	)
	(via
		(at 194.193414 -286.56661)
		(size 0.4572)
		(drill 0.2032)
		(layers "F.Cu" "B.Cu")
		(net "GND")
	)
	(via
		(at 194.193414 -262.76681)
		(size 0.4572)
		(drill 0.2032)
		(layers "F.Cu" "B.Cu")
		(net "GND")
	)
	(via
		(at 172.795946 -201.56678)
		(size 0.4572)
		(drill 0.2032)
		(layers "F.Cu" "B.Cu")
		(net "GND")
	)
	(via
		(at 88.86317 -401.492212)
		(size 0.4572)
		(drill 0.254)
		(layers "F.Cu" "B.Cu")
		(net "GND")
	)
	(via
		(at 383.431034 -60.719462)
		(size 0.508)
		(drill 0.254)
		(layers "F.Cu" "B.Cu")
		(net "GND")
	)
	(via
		(at 58.608214 -232.166668)
		(size 0.4572)
		(drill 0.2032)
		(layers "F.Cu" "B.Cu")
		(net "GND")
	)
	(via
		(at 84.26704 -179.294028)
		(size 0.508)
		(drill 0.254)
		(layers "F.Cu" "B.Cu")
		(net "GND")
	)
	(via
		(at 127.616712 -227.64496)
		(size 0.4572)
		(drill 0.2032)
		(layers "F.Cu" "B.Cu")
		(net "GND")
	)
	(via
		(at 349.634048 -410.030168)
		(size 0.4064)
		(drill 0.2032)
		(layers "F.Cu" "B.Cu")
		(net "GND")
	)
	(via
		(at 312.51398 -409.396184)
		(size 0.4572)
		(drill 0.254)
		(layers "F.Cu" "B.Cu")
		(net "GND")
	)
	(via
		(at 421.23106 -359.414572)
		(size 0.508)
		(drill 0.254)
		(layers "F.Cu" "B.Cu")
		(net "GND")
	)
	(via
		(at 317.020448 -407.00452)
		(size 0.4064)
		(drill 0.2032)
		(layers "F.Cu" "B.Cu")
		(net "GND")
	)
	(via
		(at 31.876746 -260.21665)
		(size 0.4572)
		(drill 0.2032)
		(layers "F.Cu" "B.Cu")
		(net "GND")
	)
	(via
		(at 137.768838 -340.977728)
		(size 0.49022)
		(drill 0.254)
		(layers "F.Cu" "B.Cu")
		(net "GND")
	)
	(via
		(at 159.918146 -315.46673)
		(size 0.4572)
		(drill 0.2032)
		(layers "F.Cu" "B.Cu")
		(net "GND")
	)
	(via
		(at 179.105814 -200.716642)
		(size 0.4572)
		(drill 0.2032)
		(layers "F.Cu" "B.Cu")
		(net "GND")
	)
	(via
		(at 352.062034 -232.528364)
		(size 0.4572)
		(drill 0.2032)
		(layers "F.Cu" "B.Cu")
		(net "GND")
	)
	(via
		(at 439.923682 -261.066788)
		(size 0.4572)
		(drill 0.2032)
		(layers "F.Cu" "B.Cu")
		(net "GND")
	)
	(via
		(at 409.69692 -175.707548)
		(size 0.508)
		(drill 0.254)
		(layers "F.Cu" "B.Cu")
		(net "GND")
	)
	(via
		(at 159.82188 -118.836948)
		(size 0.508)
		(drill 0.254)
		(layers "F.Cu" "B.Cu")
		(net "GND")
	)
	(via
		(at 307.782214 -233.016806)
		(size 0.4572)
		(drill 0.2032)
		(layers "F.Cu" "B.Cu")
		(net "GND")
	)
	(via
		(at 43.91533 -441.225432)
		(size 0.508)
		(drill 0.254)
		(layers "F.Cu" "B.Cu")
		(net "GND")
	)
	(via
		(at 197.637146 -270.416782)
		(size 0.4572)
		(drill 0.2032)
		(layers "F.Cu" "B.Cu")
		(net "GND")
	)
	(via
		(at 374.726962 -275.08073)
		(size 0.4572)
		(drill 0.2032)
		(layers "F.Cu" "B.Cu")
		(net "GND")
	)
	(via
		(at 158.336234 -400.858228)
		(size 0.4064)
		(drill 0.2032)
		(layers "F.Cu" "B.Cu")
		(net "GND")
	)
	(via
		(at 98.953066 -213.732618)
		(size 0.4572)
		(drill 0.2032)
		(layers "F.Cu" "B.Cu")
		(net "GND")
	)
	(via
		(at 358.170734 -220.319854)
		(size 0.4572)
		(drill 0.2032)
		(layers "F.Cu" "B.Cu")
		(net "GND")
	)
	(via
		(at 102.712012 -233.34218)
		(size 0.4572)
		(drill 0.2032)
		(layers "F.Cu" "B.Cu")
		(net "GND")
	)
	(via
		(at 199.527414 -312.91657)
		(size 0.4572)
		(drill 0.2032)
		(layers "F.Cu" "B.Cu")
		(net "GND")
	)
	(via
		(at 127.903986 -356.87635)
		(size 0.508)
		(drill 0.254)
		(layers "F.Cu" "B.Cu")
		(net "GND")
	)
	(via
		(at 217.000582 -70.133718)
		(size 0.508)
		(drill 0.254)
		(layers "F.Cu" "B.Cu")
		(net "GND")
	)
	(via
		(at 254.975614 -272.116804)
		(size 0.4572)
		(drill 0.2032)
		(layers "F.Cu" "B.Cu")
		(net "GND")
	)
	(via
		(at 429.851312 -4.317746)
		(size 0.508)
		(drill 0.254)
		(layers "F.Cu" "B.Cu")
		(net "GND")
	)
	(via
		(at 422.66616 -144.689068)
		(size 0.508)
		(drill 0.254)
		(layers "F.Cu" "B.Cu")
		(net "GND")
	)
	(via
		(at 419.809676 -291.666676)
		(size 0.4572)
		(drill 0.2032)
		(layers "F.Cu" "B.Cu")
		(net "GND")
	)
	(via
		(at 407.858214 -214.316564)
		(size 0.4572)
		(drill 0.2032)
		(layers "F.Cu" "B.Cu")
		(net "GND")
	)
	(via
		(at 383.185416 -265.314176)
		(size 0.4572)
		(drill 0.2032)
		(layers "F.Cu" "B.Cu")
		(net "GND")
	)
	(via
		(at 124.45492 -63.630048)
		(size 0.508)
		(drill 0.254)
		(layers "F.Cu" "B.Cu")
		(net "GND")
	)
	(via
		(at 164.063172 -219.41663)
		(size 0.4572)
		(drill 0.2032)
		(layers "F.Cu" "B.Cu")
		(net "GND")
	)
	(via
		(at 272.273014 -195.616576)
		(size 0.4572)
		(drill 0.2032)
		(layers "F.Cu" "B.Cu")
		(net "GND")
	)
	(via
		(at 386.364734 -220.319854)
		(size 0.4572)
		(drill 0.2032)
		(layers "F.Cu" "B.Cu")
		(net "GND")
	)
	(via
		(at 411.355286 -182.999126)
		(size 0.508)
		(drill 0.254)
		(layers "F.Cu" "B.Cu")
		(net "GND")
	)
	(via
		(at 136.349994 -434.899562)
		(size 0.4572)
		(drill 0.2032)
		(layers "F.Cu" "B.Cu")
		(net "GND")
	)
	(via
		(at 37.940234 -112.619282)
		(size 0.508)
		(drill 0.254)
		(layers "F.Cu" "B.Cu")
		(net "GND")
	)
	(via
		(at 419.502082 -280.61666)
		(size 0.4572)
		(drill 0.2032)
		(layers "F.Cu" "B.Cu")
		(net "GND")
	)
	(via
		(at 336.250026 -435.0512)
		(size 0.4572)
		(drill 0.2032)
		(layers "F.Cu" "B.Cu")
		(net "GND")
	)
	(via
		(at 41.310814 -294.216582)
		(size 0.4572)
		(drill 0.2032)
		(layers "F.Cu" "B.Cu")
		(net "GND")
	)
	(via
		(at 94.98965 -404.51786)
		(size 0.4572)
		(drill 0.254)
		(layers "F.Cu" "B.Cu")
		(net "GND")
	)
	(via
		(at 409.748482 -316.316614)
		(size 0.4572)
		(drill 0.2032)
		(layers "F.Cu" "B.Cu")
		(net "GND")
	)
	(via
		(at 137.484866 -223.575626)
		(size 0.4572)
		(drill 0.2032)
		(layers "F.Cu" "B.Cu")
		(net "GND")
	)
	(via
		(at 29.619194 -6.090412)
		(size 0.508)
		(drill 0.254)
		(layers "F.Cu" "B.Cu")
		(net "GND")
	)
	(via
		(at 266.79906 -153.459688)
		(size 0.508)
		(drill 0.254)
		(layers "F.Cu" "B.Cu")
		(net "GND")
	)
	(via
		(at 409.748482 -250.866656)
		(size 0.4572)
		(drill 0.2032)
		(layers "F.Cu" "B.Cu")
		(net "GND")
	)
	(via
		(at 94.253812 -243.108988)
		(size 0.4572)
		(drill 0.2032)
		(layers "F.Cu" "B.Cu")
		(net "GND")
	)
	(via
		(at 422.55186 -360.735372)
		(size 0.508)
		(drill 0.254)
		(layers "F.Cu" "B.Cu")
		(net "GND")
	)
	(via
		(at 18.130266 -18.502376)
		(size 0.508)
		(drill 0.254)
		(layers "F.Cu" "B.Cu")
		(net "GND")
	)
	(via
		(at 43.520614 -202.416664)
		(size 0.4572)
		(drill 0.2032)
		(layers "F.Cu" "B.Cu")
		(net "GND")
	)
	(via
		(at 291.460682 -267.866622)
		(size 0.4572)
		(drill 0.2032)
		(layers "F.Cu" "B.Cu")
		(net "GND")
	)
	(via
		(at 147.4216 -76.810108)
		(size 0.508)
		(drill 0.254)
		(layers "F.Cu" "B.Cu")
		(net "GND")
	)
	(via
		(at 345.013534 -230.086662)
		(size 0.4572)
		(drill 0.2032)
		(layers "F.Cu" "B.Cu")
		(net "GND")
	)
	(via
		(at 345.95308 -246.364506)
		(size 0.4572)
		(drill 0.2032)
		(layers "F.Cu" "B.Cu")
		(net "GND")
	)
	(via
		(at 114.459766 -222.761556)
		(size 0.4572)
		(drill 0.2032)
		(layers "F.Cu" "B.Cu")
		(net "GND")
	)
	(via
		(at 300.238414 -301.866808)
		(size 0.4572)
		(drill 0.2032)
		(layers "F.Cu" "B.Cu")
		(net "GND")
	)
	(via
		(at 209.281014 -224.516696)
		(size 0.4572)
		(drill 0.2032)
		(layers "F.Cu" "B.Cu")
		(net "GND")
	)
	(via
		(at 295.077896 -360.173524)
		(size 0.508)
		(drill 0.254)
		(layers "F.Cu" "B.Cu")
		(net "GND")
	)
	(via
		(at 154.40406 -8.734806)
		(size 0.508)
		(drill 0.254)
		(layers "F.Cu" "B.Cu")
		(net "GND")
	)
	(via
		(at 157.708346 -251.716794)
		(size 0.4572)
		(drill 0.2032)
		(layers "F.Cu" "B.Cu")
		(net "GND")
	)
	(via
		(at 361.460034 -235.783882)
		(size 0.4572)
		(drill 0.2032)
		(layers "F.Cu" "B.Cu")
		(net "GND")
	)
	(via
		(at 54.724046 -234.716574)
		(size 0.4572)
		(drill 0.2032)
		(layers "F.Cu" "B.Cu")
		(net "GND")
	)
	(via
		(at 450.911214 -281.466798)
		(size 0.4572)
		(drill 0.2032)
		(layers "F.Cu" "B.Cu")
		(net "GND")
	)
	(via
		(at 24.332946 -199.01662)
		(size 0.4572)
		(drill 0.2032)
		(layers "F.Cu" "B.Cu")
		(net "GND")
	)
	(via
		(at 180.114194 -411.185868)
		(size 0.508)
		(drill 0.254)
		(layers "F.Cu" "B.Cu")
		(net "GND")
	)
	(via
		(at 370.968016 -271.825212)
		(size 0.4572)
		(drill 0.2032)
		(layers "F.Cu" "B.Cu")
		(net "GND")
	)
	(via
		(at 339.484716 -259.616956)
		(size 0.4572)
		(drill 0.2032)
		(layers "F.Cu" "B.Cu")
		(net "GND")
	)
	(via
		(at 345.013534 -223.575626)
		(size 0.4572)
		(drill 0.2032)
		(layers "F.Cu" "B.Cu")
		(net "GND")
	)
	(via
		(at 370.38788 -236.597952)
		(size 0.4572)
		(drill 0.2032)
		(layers "F.Cu" "B.Cu")
		(net "GND")
	)
	(via
		(at 370.51488 -38.953948)
		(size 0.508)
		(drill 0.254)
		(layers "F.Cu" "B.Cu")
		(net "GND")
	)
	(via
		(at 262.519414 -225.36658)
		(size 0.4572)
		(drill 0.2032)
		(layers "F.Cu" "B.Cu")
		(net "GND")
	)
	(via
		(at 58.608214 -245.76659)
		(size 0.4572)
		(drill 0.2032)
		(layers "F.Cu" "B.Cu")
		(net "GND")
	)
	(via
		(at 455.011282 -249.166634)
		(size 0.4572)
		(drill 0.2032)
		(layers "F.Cu" "B.Cu")
		(net "GND")
	)
	(via
		(at 103.80599 -332.56601)
		(size 0.49022)
		(drill 0.254)
		(layers "F.Cu" "B.Cu")
		(net "GND")
	)
	(via
		(at 296.794682 -305.266598)
		(size 0.4572)
		(drill 0.2032)
		(layers "F.Cu" "B.Cu")
		(net "GND")
	)
	(via
		(at 283.916882 -277.216616)
		(size 0.4572)
		(drill 0.2032)
		(layers "F.Cu" "B.Cu")
		(net "GND")
	)
	(via
		(at 398.69745 -410.030168)
		(size 0.4064)
		(drill 0.2032)
		(layers "F.Cu" "B.Cu")
		(net "GND")
	)
	(via
		(at 180.339746 -246.616728)
		(size 0.4572)
		(drill 0.2032)
		(layers "F.Cu" "B.Cu")
		(net "GND")
	)
	(via
		(at 97.183448 -272.639282)
		(size 0.4572)
		(drill 0.2032)
		(layers "F.Cu" "B.Cu")
		(net "GND")
	)
	(via
		(at 119.87276 -151.773128)
		(size 0.508)
		(drill 0.254)
		(layers "F.Cu" "B.Cu")
		(net "GND")
	)
	(via
		(at 460.664814 -300.166786)
		(size 0.4572)
		(drill 0.2032)
		(layers "F.Cu" "B.Cu")
		(net "GND")
	)
	(via
		(at 214.615014 -215.166702)
		(size 0.4572)
		(drill 0.2032)
		(layers "F.Cu" "B.Cu")
		(net "GND")
	)
	(via
		(at 131.956048 -272.639282)
		(size 0.4572)
		(drill 0.2032)
		(layers "F.Cu" "B.Cu")
		(net "GND")
	)
	(via
		(at 289.250882 -278.916638)
		(size 0.4572)
		(drill 0.2032)
		(layers "F.Cu" "B.Cu")
		(net "GND")
	)
	(via
		(at 176.896014 -310.366664)
		(size 0.4572)
		(drill 0.2032)
		(layers "F.Cu" "B.Cu")
		(net "GND")
	)
	(via
		(at 110.340394 -259.61721)
		(size 0.4572)
		(drill 0.2032)
		(layers "F.Cu" "B.Cu")
		(net "GND")
	)
	(via
		(at 52.298346 -260.21665)
		(size 0.4572)
		(drill 0.2032)
		(layers "F.Cu" "B.Cu")
		(net "GND")
	)
	(via
		(at 462.555082 -264.466578)
		(size 0.4572)
		(drill 0.2032)
		(layers "F.Cu" "B.Cu")
		(net "GND")
	)
	(via
		(at 117.749066 -213.732618)
		(size 0.4572)
		(drill 0.2032)
		(layers "F.Cu" "B.Cu")
		(net "GND")
	)
	(via
		(at 457.221082 -297.616626)
		(size 0.4572)
		(drill 0.2032)
		(layers "F.Cu" "B.Cu")
		(net "GND")
	)
	(via
		(at 145.2118 -140.2588)
		(size 0.508)
		(drill 0.254)
		(layers "F.Cu" "B.Cu")
		(net "GND")
	)
	(via
		(at 438.033414 -279.766776)
		(size 0.4572)
		(drill 0.2032)
		(layers "F.Cu" "B.Cu")
		(net "GND")
	)
	(via
		(at 70.33006 -63.251588)
		(size 0.508)
		(drill 0.254)
		(layers "F.Cu" "B.Cu")
		(net "GND")
	)
	(via
		(at 59.842146 -306.116736)
		(size 0.4572)
		(drill 0.2032)
		(layers "F.Cu" "B.Cu")
		(net "GND")
	)
	(via
		(at 24.332946 -208.366614)
		(size 0.4572)
		(drill 0.2032)
		(layers "F.Cu" "B.Cu")
		(net "GND")
	)
	(via
		(at 307.782214 -289.11677)
		(size 0.4572)
		(drill 0.2032)
		(layers "F.Cu" "B.Cu")
		(net "GND")
	)
	(via
		(at 168.510966 -410.664152)
		(size 0.4572)
		(drill 0.254)
		(layers "F.Cu" "B.Cu")
		(net "GND")
	)
	(via
		(at 120.678194 -274.266914)
		(size 0.4572)
		(drill 0.2032)
		(layers "F.Cu" "B.Cu")
		(net "GND")
	)
	(via
		(at 198.9074 -150.769828)
		(size 0.508)
		(drill 0.254)
		(layers "F.Cu" "B.Cu")
		(net "GND")
	)
	(via
		(at 453.121014 -217.716608)
		(size 0.4572)
		(drill 0.2032)
		(layers "F.Cu" "B.Cu")
		(net "GND")
	)
	(via
		(at 184.439814 -277.216616)
		(size 0.4572)
		(drill 0.2032)
		(layers "F.Cu" "B.Cu")
		(net "GND")
	)
	(via
		(at 39.420546 -250.016772)
		(size 0.4572)
		(drill 0.2032)
		(layers "F.Cu" "B.Cu")
		(net "GND")
	)
	(via
		(at 283.916882 -264.466578)
		(size 0.4572)
		(drill 0.2032)
		(layers "F.Cu" "B.Cu")
		(net "GND")
	)
	(via
		(at 435.823614 -296.766742)
		(size 0.4572)
		(drill 0.2032)
		(layers "F.Cu" "B.Cu")
		(net "GND")
	)
	(via
		(at 341.098378 -42.341546)
		(size 0.4572)
		(drill 0.2032)
		(layers "F.Cu" "B.Cu")
		(net "GND")
	)
	(via
		(at 337.134962 -283.219906)
		(size 0.4572)
		(drill 0.2032)
		(layers "F.Cu" "B.Cu")
		(net "GND")
	)
	(via
		(at 443.367414 -214.316564)
		(size 0.4572)
		(drill 0.2032)
		(layers "F.Cu" "B.Cu")
		(net "GND")
	)
	(via
		(at 37.210746 -260.21665)
		(size 0.4572)
		(drill 0.2032)
		(layers "F.Cu" "B.Cu")
		(net "GND")
	)
	(via
		(at 344.25001 -425.547282)
		(size 0.4572)
		(drill 0.2032)
		(layers "F.Cu" "B.Cu")
		(net "GND")
	)
	(via
		(at 428.27829 -354.182172)
		(size 0.508)
		(drill 0.254)
		(layers "F.Cu" "B.Cu")
		(net "GND")
	)
	(via
		(at 110.340648 -254.733806)
		(size 0.4572)
		(drill 0.2032)
		(layers "F.Cu" "B.Cu")
		(net "GND")
	)
	(via
		(at 175.231552 -208.366614)
		(size 0.4572)
		(drill 0.2032)
		(layers "F.Cu" "B.Cu")
		(net "GND")
	)
	(via
		(at 300.238414 -221.96679)
		(size 0.4572)
		(drill 0.2032)
		(layers "F.Cu" "B.Cu")
		(net "GND")
	)
	(via
		(at 410.589222 -407.638504)
		(size 0.4572)
		(drill 0.254)
		(layers "F.Cu" "B.Cu")
		(net "GND")
	)
	(via
		(at 369.088162 -286.475424)
		(size 0.4572)
		(drill 0.2032)
		(layers "F.Cu" "B.Cu")
		(net "GND")
	)
	(via
		(at 124.750068 -366.093248)
		(size 0.508)
		(drill 0.254)
		(layers "F.Cu" "B.Cu")
		(net "GND")
	)
	(via
		(at 340.180168 -400.858228)
		(size 0.4064)
		(drill 0.2032)
		(layers "F.Cu" "B.Cu")
		(net "GND")
	)
	(via
		(at 179.384706 -345.648788)
		(size 0.508)
		(drill 0.254)
		(layers "F.Cu" "B.Cu")
		(net "GND")
	)
	(via
		(at 302.664114 -220.266768)
		(size 0.4572)
		(drill 0.2032)
		(layers "F.Cu" "B.Cu")
		(net "GND")
	)
	(via
		(at 50.484278 -403.883876)
		(size 0.4064)
		(drill 0.2032)
		(layers "F.Cu" "B.Cu")
		(net "GND")
	)
	(via
		(at 183.929782 -35.887152)
		(size 0.508)
		(drill 0.254)
		(layers "F.Cu" "B.Cu")
		(net "GND")
	)
	(via
		(at 362.399834 -216.25052)
		(size 0.4572)
		(drill 0.2032)
		(layers "F.Cu" "B.Cu")
		(net "GND")
	)
	(via
		(at 128.688846 -406.370536)
		(size 0.4572)
		(drill 0.254)
		(layers "F.Cu" "B.Cu")
		(net "GND")
	)
	(via
		(at 94.723966 -222.761556)
		(size 0.4572)
		(drill 0.2032)
		(layers "F.Cu" "B.Cu")
		(net "GND")
	)
	(via
		(at 216.824814 -308.666642)
		(size 0.4572)
		(drill 0.2032)
		(layers "F.Cu" "B.Cu")
		(net "GND")
	)
	(via
		(at 332.326234 -234.15625)
		(size 0.4572)
		(drill 0.2032)
		(layers "F.Cu" "B.Cu")
		(net "GND")
	)
	(via
		(at 458.455014 -306.116736)
		(size 0.4572)
		(drill 0.2032)
		(layers "F.Cu" "B.Cu")
		(net "GND")
	)
	(via
		(at 127.7874 -19.914108)
		(size 0.508)
		(drill 0.254)
		(layers "F.Cu" "B.Cu")
		(net "GND")
	)
	(via
		(at 383.952496 -73.95845)
		(size 0.508)
		(drill 0.254)
		(layers "F.Cu" "B.Cu")
		(net "GND")
	)
	(via
		(at 115.4303 -364.12932)
		(size 0.508)
		(drill 0.254)
		(layers "F.Cu" "B.Cu")
		(net "GND")
	)
	(via
		(at 157.975046 -401.492212)
		(size 0.4572)
		(drill 0.254)
		(layers "F.Cu" "B.Cu")
		(net "GND")
	)
	(via
		(at 46.86046 -102.159562)
		(size 0.508)
		(drill 0.254)
		(layers "F.Cu" "B.Cu")
		(net "GND")
	)
	(via
		(at 438.033414 -304.416714)
		(size 0.4572)
		(drill 0.2032)
		(layers "F.Cu" "B.Cu")
		(net "GND")
	)
	(via
		(at 334.205834 -245.55069)
		(size 0.4572)
		(drill 0.2032)
		(layers "F.Cu" "B.Cu")
		(net "GND")
	)
	(via
		(at 285.150814 -244.916706)
		(size 0.4572)
		(drill 0.2032)
		(layers "F.Cu" "B.Cu")
		(net "GND")
	)
	(via
		(at 119.738648 -287.28924)
		(size 0.4572)
		(drill 0.2032)
		(layers "F.Cu" "B.Cu")
		(net "GND")
	)
	(via
		(at 197.637146 -212.616796)
		(size 0.4572)
		(drill 0.2032)
		(layers "F.Cu" "B.Cu")
		(net "GND")
	)
	(via
		(at 159.82188 -121.376948)
		(size 0.508)
		(drill 0.254)
		(layers "F.Cu" "B.Cu")
		(net "GND")
	)
	(via
		(at 378.016262 -257.98907)
		(size 0.4572)
		(drill 0.2032)
		(layers "F.Cu" "B.Cu")
		(net "GND")
	)
	(via
		(at 140.54328 -19.670522)
		(size 0.508)
		(drill 0.254)
		(layers "F.Cu" "B.Cu")
		(net "GND")
	)
	(via
		(at 124.986796 -76.277724)
		(size 0.508)
		(drill 0.254)
		(layers "F.Cu" "B.Cu")
		(net "GND")
	)
	(via
		(at 422.945814 -225.36658)
		(size 0.4572)
		(drill 0.2032)
		(layers "F.Cu" "B.Cu")
		(net "GND")
	)
	(via
		(at 53.44287 -352.401886)
		(size 0.49022)
		(drill 0.254)
		(layers "F.Cu" "B.Cu")
		(net "GND")
	)
	(via
		(at 86.375494 -279.964134)
		(size 0.4572)
		(drill 0.2032)
		(layers "F.Cu" "B.Cu")
		(net "GND")
	)
	(via
		(at 374.726962 -265.314176)
		(size 0.4572)
		(drill 0.2032)
		(layers "F.Cu" "B.Cu")
		(net "GND")
	)
	(via
		(at 449.677282 -316.316614)
		(size 0.4572)
		(drill 0.2032)
		(layers "F.Cu" "B.Cu")
		(net "GND")
	)
	(via
		(at 384.95478 -219.506038)
		(size 0.4572)
		(drill 0.2032)
		(layers "F.Cu" "B.Cu")
		(net "GND")
	)
	(via
		(at 216.824814 -261.066788)
		(size 0.4572)
		(drill 0.2032)
		(layers "F.Cu" "B.Cu")
		(net "GND")
	)
	(via
		(at 56.532018 -170.689524)
		(size 0.508)
		(drill 0.254)
		(layers "F.Cu" "B.Cu")
		(net "GND")
	)
	(via
		(at 281.707082 -306.96662)
		(size 0.4572)
		(drill 0.2032)
		(layers "F.Cu" "B.Cu")
		(net "GND")
	)
	(via
		(at 115.415822 -244.812566)
		(size 0.4572)
		(drill 0.2032)
		(layers "F.Cu" "B.Cu")
		(net "GND")
	)
	(via
		(at 174.80788 -98.643948)
		(size 0.508)
		(drill 0.254)
		(layers "F.Cu" "B.Cu")
		(net "GND")
	)
	(via
		(at 35.976814 -291.666676)
		(size 0.4572)
		(drill 0.2032)
		(layers "F.Cu" "B.Cu")
		(net "GND")
	)
	(via
		(at 61.53277 -41.278048)
		(size 0.508)
		(drill 0.254)
		(layers "F.Cu" "B.Cu")
		(net "GND")
	)
	(via
		(at 103.319072 -410.579824)
		(size 0.508)
		(drill 0.254)
		(layers "F.Cu" "B.Cu")
		(net "GND")
	)
	(via
		(at 405.349964 -426.54728)
		(size 0.4572)
		(drill 0.2032)
		(layers "F.Cu" "B.Cu")
		(net "GND")
	)
	(via
		(at 56.60263 -5.596636)
		(size 0.508)
		(drill 0.254)
		(layers "F.Cu" "B.Cu")
		(net "GND")
	)
	(via
		(at 346.423234 -222.761556)
		(size 0.4572)
		(drill 0.2032)
		(layers "F.Cu" "B.Cu")
		(net "GND")
	)
	(via
		(at 66.152014 -200.716642)
		(size 0.4572)
		(drill 0.2032)
		(layers "F.Cu" "B.Cu")
		(net "GND")
	)
	(via
		(at 176.996852 -11.458448)
		(size 0.508)
		(drill 0.254)
		(layers "F.Cu" "B.Cu")
		(net "GND")
	)
	(via
		(at 450.911214 -270.416782)
		(size 0.4572)
		(drill 0.2032)
		(layers "F.Cu" "B.Cu")
		(net "GND")
	)
	(via
		(at 309.992014 -301.866808)
		(size 0.4572)
		(drill 0.2032)
		(layers "F.Cu" "B.Cu")
		(net "GND")
	)
	(via
		(at 403.349968 -431.451258)
		(size 0.4572)
		(drill 0.2032)
		(layers "F.Cu" "B.Cu")
		(net "GND")
	)
	(via
		(at 264.729214 -265.316716)
		(size 0.4572)
		(drill 0.2032)
		(layers "F.Cu" "B.Cu")
		(net "GND")
	)
	(via
		(at 195.427346 -273.816572)
		(size 0.4572)
		(drill 0.2032)
		(layers "F.Cu" "B.Cu")
		(net "GND")
	)
	(via
		(at 237.33252 -388.01294)
		(size 0.508)
		(drill 0.254)
		(layers "F.Cu" "B.Cu")
		(net "GND")
	)
	(via
		(at 115.460272 -20.010628)
		(size 0.508)
		(drill 0.254)
		(layers "F.Cu" "B.Cu")
		(net "GND")
	)
	(via
		(at 105.44302 -121.971308)
		(size 0.508)
		(drill 0.254)
		(layers "F.Cu" "B.Cu")
		(net "GND")
	)
	(via
		(at 164.034978 -77.289914)
		(size 0.508)
		(drill 0.254)
		(layers "F.Cu" "B.Cu")
		(net "GND")
	)
	(via
		(at 427.045882 -204.116686)
		(size 0.4572)
		(drill 0.2032)
		(layers "F.Cu" "B.Cu")
		(net "GND")
	)
	(via
		(at 415.402014 -301.866808)
		(size 0.4572)
		(drill 0.2032)
		(layers "F.Cu" "B.Cu")
		(net "GND")
	)
	(via
		(at 346.893134 -223.575626)
		(size 0.4572)
		(drill 0.2032)
		(layers "F.Cu" "B.Cu")
		(net "GND")
	)
	(via
		(at 201.737214 -205.816708)
		(size 0.4572)
		(drill 0.2032)
		(layers "F.Cu" "B.Cu")
		(net "GND")
	)
	(via
		(at 124.366782 -406.370536)
		(size 0.4572)
		(drill 0.254)
		(layers "F.Cu" "B.Cu")
		(net "GND")
	)
	(via
		(at 292.694614 -248.31675)
		(size 0.4572)
		(drill 0.2032)
		(layers "F.Cu" "B.Cu")
		(net "GND")
	)
	(via
		(at 356.291134 -226.831144)
		(size 0.4572)
		(drill 0.2032)
		(layers "F.Cu" "B.Cu")
		(net "GND")
	)
	(via
		(at 126.316994 -256.361438)
		(size 0.4572)
		(drill 0.2032)
		(layers "F.Cu" "B.Cu")
		(net "GND")
	)
	(via
		(at 210.514946 -204.96657)
		(size 0.4572)
		(drill 0.2032)
		(layers "F.Cu" "B.Cu")
		(net "GND")
	)
	(via
		(at 66.152014 -226.216718)
		(size 0.4572)
		(drill 0.2032)
		(layers "F.Cu" "B.Cu")
		(net "GND")
	)
	(via
		(at 327.15454 -336.119978)
		(size 0.508)
		(drill 0.254)
		(layers "F.Cu" "B.Cu")
		(net "GND")
	)
	(via
		(at 351.654364 -262.70458)
		(size 0.4572)
		(drill 0.2032)
		(layers "F.Cu" "B.Cu")
		(net "GND")
	)
	(via
		(at 335.61528 -215.436704)
		(size 0.4572)
		(drill 0.2032)
		(layers "F.Cu" "B.Cu")
		(net "GND")
	)
	(via
		(at 51.998118 -18.502376)
		(size 0.508)
		(drill 0.254)
		(layers "F.Cu" "B.Cu")
		(net "GND")
	)
	(via
		(at 90.25001 -436.051198)
		(size 0.4572)
		(drill 0.2032)
		(layers "F.Cu" "B.Cu")
		(net "GND")
	)
	(via
		(at 14.579346 -315.46673)
		(size 0.4572)
		(drill 0.2032)
		(layers "F.Cu" "B.Cu")
		(net "GND")
	)
	(via
		(at 20.889214 -202.416664)
		(size 0.4572)
		(drill 0.2032)
		(layers "F.Cu" "B.Cu")
		(net "GND")
	)
	(via
		(at 272.273014 -267.016738)
		(size 0.4572)
		(drill 0.2032)
		(layers "F.Cu" "B.Cu")
		(net "GND")
	)
	(via
		(at 136.185148 -271.825212)
		(size 0.4572)
		(drill 0.2032)
		(layers "F.Cu" "B.Cu")
		(net "GND")
	)
	(via
		(at 340.250018 -432.747166)
		(size 0.4572)
		(drill 0.2032)
		(layers "F.Cu" "B.Cu")
		(net "GND")
	)
	(via
		(at 185.768488 -323.459856)
		(size 0.4572)
		(drill 0.2032)
		(layers "F.Cu" "B.Cu")
		(net "GND")
	)
	(via
		(at 306.548282 -258.516628)
		(size 0.4572)
		(drill 0.2032)
		(layers "F.Cu" "B.Cu")
		(net "GND")
	)
	(via
		(at 33.767014 -233.86669)
		(size 0.4572)
		(drill 0.2032)
		(layers "F.Cu" "B.Cu")
		(net "GND")
	)
	(via
		(at 199.527414 -198.166736)
		(size 0.4572)
		(drill 0.2032)
		(layers "F.Cu" "B.Cu")
		(net "GND")
	)
	(via
		(at 128.666494 -286.475424)
		(size 0.4572)
		(drill 0.2032)
		(layers "F.Cu" "B.Cu")
		(net "GND")
	)
	(via
		(at 344.950796 -410.664152)
		(size 0.4572)
		(drill 0.254)
		(layers "F.Cu" "B.Cu")
		(net "GND")
	)
	(via
		(at 384.485134 -241.481102)
		(size 0.4318)
		(drill 0.2032)
		(layers "F.Cu" "B.Cu")
		(net "GND")
	)
	(via
		(at 14.579346 -204.96657)
		(size 0.4572)
		(drill 0.2032)
		(layers "F.Cu" "B.Cu")
		(net "GND")
	)
	(via
		(at 122.448066 -231.714548)
		(size 0.4572)
		(drill 0.2032)
		(layers "F.Cu" "B.Cu")
		(net "GND")
	)
	(via
		(at 97.653094 -257.175254)
		(size 0.4572)
		(drill 0.2032)
		(layers "F.Cu" "B.Cu")
		(net "GND")
	)
	(via
		(at 257.683 -67.782948)
		(size 0.508)
		(drill 0.254)
		(layers "F.Cu" "B.Cu")
		(net "GND")
	)
	(via
		(at 374.14708 -246.364506)
		(size 0.4572)
		(drill 0.2032)
		(layers "F.Cu" "B.Cu")
		(net "GND")
	)
	(via
		(at 57.404762 -150.93188)
		(size 0.508)
		(drill 0.254)
		(layers "F.Cu" "B.Cu")
		(net "GND")
	)
	(via
		(at 101.772212 -246.364506)
		(size 0.4572)
		(drill 0.2032)
		(layers "F.Cu" "B.Cu")
		(net "GND")
	)
	(via
		(at 116.762784 -292.95598)
		(size 0.508)
		(drill 0.254)
		(layers "F.Cu" "B.Cu")
		(net "GND")
	)
	(via
		(at 164.018214 -222.816674)
		(size 0.4572)
		(drill 0.2032)
		(layers "F.Cu" "B.Cu")
		(net "GND")
	)
	(via
		(at 333.371952 -342.481662)
		(size 0.508)
		(drill 0.254)
		(layers "F.Cu" "B.Cu")
		(net "GND")
	)
	(via
		(at 210.514946 -240.666778)
		(size 0.4572)
		(drill 0.2032)
		(layers "F.Cu" "B.Cu")
		(net "GND")
	)
	(via
		(at 376.606816 -265.314176)
		(size 0.4572)
		(drill 0.2032)
		(layers "F.Cu" "B.Cu")
		(net "GND")
	)
	(via
		(at 364.067598 -292.955726)
		(size 0.508)
		(drill 0.254)
		(layers "F.Cu" "B.Cu")
		(net "GND")
	)
	(via
		(at 384.46329 -407.00452)
		(size 0.4064)
		(drill 0.2032)
		(layers "F.Cu" "B.Cu")
		(net "GND")
	)
	(via
		(at 139.706096 -93.757242)
		(size 0.508)
		(drill 0.254)
		(layers "F.Cu" "B.Cu")
		(net "GND")
	)
	(via
		(at 125.847348 -278.336502)
		(size 0.4572)
		(drill 0.2032)
		(layers "F.Cu" "B.Cu")
		(net "GND")
	)
	(via
		(at 302.448214 -238.966756)
		(size 0.4572)
		(drill 0.2032)
		(layers "F.Cu" "B.Cu")
		(net "GND")
	)
	(via
		(at 73.634346 -409.396184)
		(size 0.4572)
		(drill 0.254)
		(layers "F.Cu" "B.Cu")
		(net "GND")
	)
	(via
		(at 355.2698 -405.8412)
		(size 0.508)
		(drill 0.254)
		(layers "F.Cu" "B.Cu")
		(net "GND")
	)
	(via
		(at 58.824114 -238.116618)
		(size 0.4572)
		(drill 0.2032)
		(layers "F.Cu" "B.Cu")
		(net "GND")
	)
	(via
		(at 457.221082 -198.166736)
		(size 0.4572)
		(drill 0.2032)
		(layers "F.Cu" "B.Cu")
		(net "GND")
	)
	(via
		(at 333.95666 -410.664152)
		(size 0.4572)
		(drill 0.254)
		(layers "F.Cu" "B.Cu")
		(net "GND")
	)
	(via
		(at 128.274572 -351.796858)
		(size 0.508)
		(drill 0.254)
		(layers "F.Cu" "B.Cu")
		(net "GND")
	)
	(via
		(at 226.949 -86.121748)
		(size 0.508)
		(drill 0.254)
		(layers "F.Cu" "B.Cu")
		(net "GND")
	)
	(via
		(at 287.912048 -363.337094)
		(size 0.49022)
		(drill 0.254)
		(layers "F.Cu" "B.Cu")
		(net "GND")
	)
	(via
		(at 14.579346 -311.216802)
		(size 0.4572)
		(drill 0.2032)
		(layers "F.Cu" "B.Cu")
		(net "GND")
	)
	(via
		(at 382.135634 -248.806208)
		(size 0.4572)
		(drill 0.2032)
		(layers "F.Cu" "B.Cu")
		(net "GND")
	)
	(via
		(at 119.33682 -93.004132)
		(size 0.508)
		(drill 0.254)
		(layers "F.Cu" "B.Cu")
		(net "GND")
	)
	(via
		(at 407.42616 -55.801768)
		(size 0.508)
		(drill 0.254)
		(layers "F.Cu" "B.Cu")
		(net "GND")
	)
	(via
		(at 349.556832 -331.043026)
		(size 0.508)
		(drill 0.254)
		(layers "F.Cu" "B.Cu")
		(net "GND")
	)
	(via
		(at 91.434412 -241.481102)
		(size 0.4572)
		(drill 0.2032)
		(layers "F.Cu" "B.Cu")
		(net "GND")
	)
	(via
		(at 266.619482 -303.566576)
		(size 0.4572)
		(drill 0.2032)
		(layers "F.Cu" "B.Cu")
		(net "GND")
	)
	(via
		(at 157.701234 -407.00452)
		(size 0.4064)
		(drill 0.2032)
		(layers "F.Cu" "B.Cu")
		(net "GND")
	)
	(via
		(at 76.644754 -30.852364)
		(size 0.508)
		(drill 0.254)
		(layers "F.Cu" "B.Cu")
		(net "GND")
	)
	(via
		(at 94.833694 -268.569694)
		(size 0.4572)
		(drill 0.2032)
		(layers "F.Cu" "B.Cu")
		(net "GND")
	)
	(via
		(at 109.290866 -238.225838)
		(size 0.4572)
		(drill 0.2032)
		(layers "F.Cu" "B.Cu")
		(net "GND")
	)
	(via
		(at 80.25003 -433.899564)
		(size 0.4572)
		(drill 0.2032)
		(layers "F.Cu" "B.Cu")
		(net "GND")
	)
	(via
		(at 73.908158 -403.883876)
		(size 0.4064)
		(drill 0.2032)
		(layers "F.Cu" "B.Cu")
		(net "GND")
	)
	(via
		(at 300.238414 -248.31675)
		(size 0.4572)
		(drill 0.2032)
		(layers "F.Cu" "B.Cu")
		(net "GND")
	)
	(via
		(at 261.285482 -269.566644)
		(size 0.4572)
		(drill 0.2032)
		(layers "F.Cu" "B.Cu")
		(net "GND")
	)
	(via
		(at 147.429474 -410.030168)
		(size 0.4064)
		(drill 0.2032)
		(layers "F.Cu" "B.Cu")
		(net "GND")
	)
	(via
		(at 435.823614 -246.616728)
		(size 0.4572)
		(drill 0.2032)
		(layers "F.Cu" "B.Cu")
		(net "GND")
	)
	(via
		(at 457.901802 -78.402434)
		(size 0.508)
		(drill 0.254)
		(layers "F.Cu" "B.Cu")
		(net "GND")
	)
	(via
		(at 309.992014 -290.816792)
		(size 0.4572)
		(drill 0.2032)
		(layers "F.Cu" "B.Cu")
		(net "GND")
	)
	(via
		(at 356.366064 -240.588292)
		(size 0.4572)
		(drill 0.2032)
		(layers "F.Cu" "B.Cu")
		(net "GND")
	)
	(via
		(at 348.014036 -407.638504)
		(size 0.4572)
		(drill 0.254)
		(layers "F.Cu" "B.Cu")
		(net "GND")
	)
	(via
		(at 61.381386 -407.638504)
		(size 0.4572)
		(drill 0.254)
		(layers "F.Cu" "B.Cu")
		(net "GND")
	)
	(via
		(at 335.725262 -274.266914)
		(size 0.4572)
		(drill 0.2032)
		(layers "F.Cu" "B.Cu")
		(net "GND")
	)
	(via
		(at 197.637146 -250.016772)
		(size 0.4572)
		(drill 0.2032)
		(layers "F.Cu" "B.Cu")
		(net "GND")
	)
	(via
		(at 157.708346 -267.016738)
		(size 0.4572)
		(drill 0.2032)
		(layers "F.Cu" "B.Cu")
		(net "GND")
	)
	(via
		(at 262.519414 -242.3668)
		(size 0.4572)
		(drill 0.2032)
		(layers "F.Cu" "B.Cu")
		(net "GND")
	)
	(via
		(at 294.904414 -214.316564)
		(size 0.4572)
		(drill 0.2032)
		(layers "F.Cu" "B.Cu")
		(net "GND")
	)
	(via
		(at 214.615014 -266.1666)
		(size 0.4572)
		(drill 0.2032)
		(layers "F.Cu" "B.Cu")
		(net "GND")
	)
	(via
		(at 365.43488 -55.884572)
		(size 0.508)
		(drill 0.254)
		(layers "F.Cu" "B.Cu")
		(net "GND")
	)
	(via
		(at 11.135614 -284.866588)
		(size 0.4572)
		(drill 0.2032)
		(layers "F.Cu" "B.Cu")
		(net "GND")
	)
	(via
		(at 346.250006 -437.34736)
		(size 0.4572)
		(drill 0.2032)
		(layers "F.Cu" "B.Cu")
		(net "GND")
	)
	(via
		(at 187.883546 -212.616796)
		(size 0.4572)
		(drill 0.2032)
		(layers "F.Cu" "B.Cu")
		(net "GND")
	)
	(via
		(at 9.245346 -265.316716)
		(size 0.4572)
		(drill 0.2032)
		(layers "F.Cu" "B.Cu")
		(net "GND")
	)
	(via
		(at 92.013786 -410.664152)
		(size 0.4572)
		(drill 0.254)
		(layers "F.Cu" "B.Cu")
		(net "GND")
	)
	(via
		(at 265.3919 -422.9227)
		(size 0.508)
		(drill 0.254)
		(layers "F.Cu" "B.Cu")
		(net "GND")
	)
	(via
		(at 16.789146 -273.816572)
		(size 0.4572)
		(drill 0.2032)
		(layers "F.Cu" "B.Cu")
		(net "GND")
	)
	(via
		(at 137.819638 -342.556084)
		(size 0.49022)
		(drill 0.254)
		(layers "F.Cu" "B.Cu")
		(net "GND")
	)
	(via
		(at 403.203918 -409.396184)
		(size 0.4572)
		(drill 0.254)
		(layers "F.Cu" "B.Cu")
		(net "GND")
	)
	(via
		(at 365.3282 -409.194)
		(size 0.508)
		(drill 0.254)
		(layers "F.Cu" "B.Cu")
		(net "GND")
	)
	(via
		(at 108.951014 -408.036014)
		(size 0.508)
		(drill 0.254)
		(layers "F.Cu" "B.Cu")
		(net "GND")
	)
	(via
		(at 333.845662 -254.733552)
		(size 0.4572)
		(drill 0.2032)
		(layers "F.Cu" "B.Cu")
		(net "GND")
	)
	(via
		(at 330.847446 -341.856314)
		(size 0.49022)
		(drill 0.254)
		(layers "F.Cu" "B.Cu")
		(net "GND")
	)
	(via
		(at 285.150814 -317.166752)
		(size 0.4572)
		(drill 0.2032)
		(layers "F.Cu" "B.Cu")
		(net "GND")
	)
	(via
		(at 304.338482 -215.166702)
		(size 0.4572)
		(drill 0.2032)
		(layers "F.Cu" "B.Cu")
		(net "GND")
	)
	(via
		(at 169.867072 -12.495022)
		(size 0.508)
		(drill 0.254)
		(layers "F.Cu" "B.Cu")
		(net "GND")
	)
	(via
		(at 68.9864 -10.201148)
		(size 0.508)
		(drill 0.254)
		(layers "F.Cu" "B.Cu")
		(net "GND")
	)
	(via
		(at 44.754546 -270.416782)
		(size 0.4572)
		(drill 0.2032)
		(layers "F.Cu" "B.Cu")
		(net "GND")
	)
	(via
		(at 430.489614 -206.666592)
		(size 0.4572)
		(drill 0.2032)
		(layers "F.Cu" "B.Cu")
		(net "GND")
	)
	(via
		(at 346.250006 -433.747164)
		(size 0.4572)
		(drill 0.2032)
		(layers "F.Cu" "B.Cu")
		(net "GND")
	)
	(via
		(at 407.34996 -425.547282)
		(size 0.4572)
		(drill 0.2032)
		(layers "F.Cu" "B.Cu")
		(net "GND")
	)
	(via
		(at 261.285482 -297.616626)
		(size 0.4572)
		(drill 0.2032)
		(layers "F.Cu" "B.Cu")
		(net "GND")
	)
	(via
		(at 278.505158 -189.07379)
		(size 0.508)
		(drill 0.254)
		(layers "F.Cu" "B.Cu")
		(net "GND")
	)
	(via
		(at 292.694614 -244.916706)
		(size 0.4572)
		(drill 0.2032)
		(layers "F.Cu" "B.Cu")
		(net "GND")
	)
	(via
		(at 266.619482 -269.566644)
		(size 0.4572)
		(drill 0.2032)
		(layers "F.Cu" "B.Cu")
		(net "GND")
	)
	(via
		(at 128.556766 -237.411514)
		(size 0.4572)
		(drill 0.2032)
		(layers "F.Cu" "B.Cu")
		(net "GND")
	)
	(via
		(at 35.976814 -238.116618)
		(size 0.4572)
		(drill 0.2032)
		(layers "F.Cu" "B.Cu")
		(net "GND")
	)
	(via
		(at 311.882282 -286.56661)
		(size 0.4572)
		(drill 0.2032)
		(layers "F.Cu" "B.Cu")
		(net "GND")
	)
	(via
		(at 405.648414 -229.616762)
		(size 0.4572)
		(drill 0.2032)
		(layers "F.Cu" "B.Cu")
		(net "GND")
	)
	(via
		(at 86.375494 -283.219906)
		(size 0.4572)
		(drill 0.2032)
		(layers "F.Cu" "B.Cu")
		(net "GND")
	)
	(via
		(at 408.161236 -204.96657)
		(size 0.4572)
		(drill 0.2032)
		(layers "F.Cu" "B.Cu")
		(net "GND")
	)
	(via
		(at 261.285482 -226.216718)
		(size 0.4572)
		(drill 0.2032)
		(layers "F.Cu" "B.Cu")
		(net "GND")
	)
	(via
		(at 291.460682 -211.766658)
		(size 0.4572)
		(drill 0.2032)
		(layers "F.Cu" "B.Cu")
		(net "GND")
	)
	(via
		(at 175.005746 -238.966756)
		(size 0.4572)
		(drill 0.2032)
		(layers "F.Cu" "B.Cu")
		(net "GND")
	)
	(via
		(at 413.192214 -210.916774)
		(size 0.4572)
		(drill 0.2032)
		(layers "F.Cu" "B.Cu")
		(net "GND")
	)
	(via
		(at 428.279814 -272.116804)
		(size 0.4572)
		(drill 0.2032)
		(layers "F.Cu" "B.Cu")
		(net "GND")
	)
	(via
		(at 87.205058 -217.878406)
		(size 0.4572)
		(drill 0.2032)
		(layers "F.Cu" "B.Cu")
		(net "GND")
	)
	(via
		(at 336.55508 -230.086662)
		(size 0.4572)
		(drill 0.2032)
		(layers "F.Cu" "B.Cu")
		(net "GND")
	)
	(via
		(at 128.556512 -227.64496)
		(size 0.4572)
		(drill 0.2032)
		(layers "F.Cu" "B.Cu")
		(net "GND")
	)
	(via
		(at 294.904414 -197.316598)
		(size 0.4572)
		(drill 0.2032)
		(layers "F.Cu" "B.Cu")
		(net "GND")
	)
	(via
		(at 91.074748 -268.569694)
		(size 0.4572)
		(drill 0.2032)
		(layers "F.Cu" "B.Cu")
		(net "GND")
	)
	(via
		(at 97.421446 -338.835492)
		(size 0.508)
		(drill 0.254)
		(layers "F.Cu" "B.Cu")
		(net "GND")
	)
	(via
		(at 130.076194 -262.872474)
		(size 0.4572)
		(drill 0.2032)
		(layers "F.Cu" "B.Cu")
		(net "GND")
	)
	(via
		(at 24.97709 -18.502376)
		(size 0.508)
		(drill 0.254)
		(layers "F.Cu" "B.Cu")
		(net "GND")
	)
	(via
		(at 216.824814 -280.61666)
		(size 0.4572)
		(drill 0.2032)
		(layers "F.Cu" "B.Cu")
		(net "GND")
	)
	(via
		(at 274.163282 -200.716642)
		(size 0.4572)
		(drill 0.2032)
		(layers "F.Cu" "B.Cu")
		(net "GND")
	)
	(via
		(at 285.150814 -240.666778)
		(size 0.4572)
		(drill 0.2032)
		(layers "F.Cu" "B.Cu")
		(net "GND")
	)
	(via
		(at 33.767014 -232.166668)
		(size 0.4572)
		(drill 0.2032)
		(layers "F.Cu" "B.Cu")
		(net "GND")
	)
	(via
		(at 28.433014 -258.516628)
		(size 0.4572)
		(drill 0.2032)
		(layers "F.Cu" "B.Cu")
		(net "GND")
	)
	(via
		(at 434.589682 -224.516696)
		(size 0.4572)
		(drill 0.2032)
		(layers "F.Cu" "B.Cu")
		(net "GND")
	)
	(via
		(at 321.250056 -439.651394)
		(size 0.4572)
		(drill 0.2032)
		(layers "F.Cu" "B.Cu")
		(net "GND")
	)
	(via
		(at 165.252146 -206.666592)
		(size 0.4572)
		(drill 0.2032)
		(layers "F.Cu" "B.Cu")
		(net "GND")
	)
	(via
		(at 194.193414 -222.816674)
		(size 0.4572)
		(drill 0.2032)
		(layers "F.Cu" "B.Cu")
		(net "GND")
	)
	(via
		(at 309.992014 -278.066754)
		(size 0.4572)
		(drill 0.2032)
		(layers "F.Cu" "B.Cu")
		(net "GND")
	)
	(via
		(at 122.448066 -236.597952)
		(size 0.4572)
		(drill 0.2032)
		(layers "F.Cu" "B.Cu")
		(net "GND")
	)
	(via
		(at 100.30714 -415.87928)
		(size 0.508)
		(drill 0.254)
		(layers "F.Cu" "B.Cu")
		(net "GND")
	)
	(via
		(at 307.782214 -236.416596)
		(size 0.4572)
		(drill 0.2032)
		(layers "F.Cu" "B.Cu")
		(net "GND")
	)
	(via
		(at 124.279406 -403.249892)
		(size 0.4572)
		(drill 0.254)
		(layers "F.Cu" "B.Cu")
		(net "GND")
	)
	(via
		(at 297.41622 -417.990528)
		(size 0.508)
		(drill 0.254)
		(layers "F.Cu" "B.Cu")
		(net "GND")
	)
	(via
		(at 336.085434 -243.922804)
		(size 0.4572)
		(drill 0.2032)
		(layers "F.Cu" "B.Cu")
		(net "GND")
	)
	(via
		(at 56.744362 -160.22828)
		(size 0.508)
		(drill 0.254)
		(layers "F.Cu" "B.Cu")
		(net "GND")
	)
	(via
		(at 417.292282 -244.066568)
		(size 0.4572)
		(drill 0.2032)
		(layers "F.Cu" "B.Cu")
		(net "GND")
	)
	(via
		(at 100.002594 -287.28924)
		(size 0.4572)
		(drill 0.2032)
		(layers "F.Cu" "B.Cu")
		(net "GND")
	)
	(via
		(at 372.377462 -282.405836)
		(size 0.4572)
		(drill 0.2032)
		(layers "F.Cu" "B.Cu")
		(net "GND")
	)
	(via
		(at 129.606294 -253.919736)
		(size 0.4572)
		(drill 0.2032)
		(layers "F.Cu" "B.Cu")
		(net "GND")
	)
	(via
		(at 319.098676 -401.492212)
		(size 0.4572)
		(drill 0.254)
		(layers "F.Cu" "B.Cu")
		(net "GND")
	)
	(via
		(at 471.03538 -38.704266)
		(size 0.508)
		(drill 0.254)
		(layers "F.Cu" "B.Cu")
		(net "GND")
	)
	(via
		(at 429.37684 -359.455466)
		(size 0.508)
		(drill 0.254)
		(layers "F.Cu" "B.Cu")
		(net "GND")
	)
	(via
		(at 127.624586 -353.828858)
		(size 0.508)
		(drill 0.254)
		(layers "F.Cu" "B.Cu")
		(net "GND")
	)
	(via
		(at 187.65774 -354.75291)
		(size 0.508)
		(drill 0.254)
		(layers "F.Cu" "B.Cu")
		(net "GND")
	)
	(via
		(at 103.618792 -295.03878)
		(size 0.508)
		(drill 0.254)
		(layers "F.Cu" "B.Cu")
		(net "GND")
	)
	(via
		(at 380.25578 -235.783882)
		(size 0.4572)
		(drill 0.2032)
		(layers "F.Cu" "B.Cu")
		(net "GND")
	)
	(via
		(at 420.736014 -313.766708)
		(size 0.4572)
		(drill 0.2032)
		(layers "F.Cu" "B.Cu")
		(net "GND")
	)
	(via
		(at 184.439814 -305.266598)
		(size 0.4572)
		(drill 0.2032)
		(layers "F.Cu" "B.Cu")
		(net "GND")
	)
	(via
		(at 349.731076 -400.224244)
		(size 0.4572)
		(drill 0.254)
		(layers "F.Cu" "B.Cu")
		(net "GND")
	)
	(via
		(at 329.908408 -400.858228)
		(size 0.4064)
		(drill 0.2032)
		(layers "F.Cu" "B.Cu")
		(net "GND")
	)
	(via
		(at 29.186886 -164.827204)
		(size 0.508)
		(drill 0.254)
		(layers "F.Cu" "B.Cu")
		(net "GND")
	)
	(via
		(at 35.976814 -282.316682)
		(size 0.4572)
		(drill 0.2032)
		(layers "F.Cu" "B.Cu")
		(net "GND")
	)
	(via
		(at 435.823614 -287.416748)
		(size 0.4572)
		(drill 0.2032)
		(layers "F.Cu" "B.Cu")
		(net "GND")
	)
	(via
		(at 14.426946 -394.231876)
		(size 0.508)
		(drill 0.254)
		(layers "F.Cu" "B.Cu")
		(net "GND")
	)
	(via
		(at 33.767014 -288.266632)
		(size 0.4572)
		(drill 0.2032)
		(layers "F.Cu" "B.Cu")
		(net "GND")
	)
	(via
		(at 41.310814 -215.166702)
		(size 0.4572)
		(drill 0.2032)
		(layers "F.Cu" "B.Cu")
		(net "GND")
	)
	(via
		(at 97.543366 -226.017328)
		(size 0.4572)
		(drill 0.2032)
		(layers "F.Cu" "B.Cu")
		(net "GND")
	)
	(via
		(at 433.708556 -323.454776)
		(size 0.4572)
		(drill 0.2032)
		(layers "F.Cu" "B.Cu")
		(net "GND")
	)
	(via
		(at 427.045882 -239.81664)
		(size 0.4572)
		(drill 0.2032)
		(layers "F.Cu" "B.Cu")
		(net "GND")
	)
	(via
		(at 268.829282 -295.916604)
		(size 0.4572)
		(drill 0.2032)
		(layers "F.Cu" "B.Cu")
		(net "GND")
	)
	(via
		(at 287.360614 -246.616728)
		(size 0.4572)
		(drill 0.2032)
		(layers "F.Cu" "B.Cu")
		(net "GND")
	)
	(via
		(at 259.075682 -230.466646)
		(size 0.4572)
		(drill 0.2032)
		(layers "F.Cu" "B.Cu")
		(net "GND")
	)
	(via
		(at 190.093346 -206.666592)
		(size 0.4572)
		(drill 0.2032)
		(layers "F.Cu" "B.Cu")
		(net "GND")
	)
	(via
		(at 458.455014 -229.616762)
		(size 0.4572)
		(drill 0.2032)
		(layers "F.Cu" "B.Cu")
		(net "GND")
	)
	(via
		(at 201.737214 -286.56661)
		(size 0.4572)
		(drill 0.2032)
		(layers "F.Cu" "B.Cu")
		(net "GND")
	)
	(via
		(at 94.833948 -262.058658)
		(size 0.4572)
		(drill 0.2032)
		(layers "F.Cu" "B.Cu")
		(net "GND")
	)
	(via
		(at 401.349972 -438.499758)
		(size 0.4572)
		(drill 0.2032)
		(layers "F.Cu" "B.Cu")
		(net "GND")
	)
	(via
		(at 420.048944 -154.186382)
		(size 0.49022)
		(drill 0.254)
		(layers "F.Cu" "B.Cu")
		(net "GND")
	)
	(via
		(at 92.844366 -239.0394)
		(size 0.4572)
		(drill 0.2032)
		(layers "F.Cu" "B.Cu")
		(net "GND")
	)
	(via
		(at 116.339366 -216.25052)
		(size 0.4572)
		(drill 0.2032)
		(layers "F.Cu" "B.Cu")
		(net "GND")
	)
	(via
		(at 99.062794 -287.28924)
		(size 0.4572)
		(drill 0.2032)
		(layers "F.Cu" "B.Cu")
		(net "GND")
	)
	(via
		(at 345.123516 -267.755878)
		(size 0.4572)
		(drill 0.2032)
		(layers "F.Cu" "B.Cu")
		(net "GND")
	)
	(via
		(at 26.018998 -6.090412)
		(size 0.508)
		(drill 0.254)
		(layers "F.Cu" "B.Cu")
		(net "GND")
	)
	(via
		(at 328.625708 -49.390046)
		(size 0.4572)
		(drill 0.2032)
		(layers "F.Cu" "B.Cu")
		(net "GND")
	)
	(via
		(at 307.782214 -268.71676)
		(size 0.4572)
		(drill 0.2032)
		(layers "F.Cu" "B.Cu")
		(net "GND")
	)
	(via
		(at 165.048946 -276.366732)
		(size 0.4572)
		(drill 0.2032)
		(layers "F.Cu" "B.Cu")
		(net "GND")
	)
	(via
		(at 239.478058 -107.376722)
		(size 0.508)
		(drill 0.254)
		(layers "F.Cu" "B.Cu")
		(net "GND")
	)
	(via
		(at 128.196594 -257.98907)
		(size 0.4572)
		(drill 0.2032)
		(layers "F.Cu" "B.Cu")
		(net "GND")
	)
	(via
		(at 54.508146 -221.96679)
		(size 0.4572)
		(drill 0.2032)
		(layers "F.Cu" "B.Cu")
		(net "GND")
	)
	(via
		(at 296.794682 -266.1666)
		(size 0.4572)
		(drill 0.2032)
		(layers "F.Cu" "B.Cu")
		(net "GND")
	)
	(via
		(at 33.767014 -310.366664)
		(size 0.4572)
		(drill 0.2032)
		(layers "F.Cu" "B.Cu")
		(net "GND")
	)
	(via
		(at 408.194256 -313.766708)
		(size 0.4572)
		(drill 0.2032)
		(layers "F.Cu" "B.Cu")
		(net "GND")
	)
	(via
		(at 90.494866 -239.853216)
		(size 0.4572)
		(drill 0.2032)
		(layers "F.Cu" "B.Cu")
		(net "GND")
	)
	(via
		(at 344.183462 -261.244842)
		(size 0.4572)
		(drill 0.2032)
		(layers "F.Cu" "B.Cu")
		(net "GND")
	)
	(via
		(at 409.401772 -19.759422)
		(size 0.508)
		(drill 0.254)
		(layers "F.Cu" "B.Cu")
		(net "GND")
	)
	(via
		(at 79.532226 -333.529432)
		(size 0.508)
		(drill 0.254)
		(layers "F.Cu" "B.Cu")
		(net "GND")
	)
	(via
		(at 346.250006 -426.54728)
		(size 0.4572)
		(drill 0.2032)
		(layers "F.Cu" "B.Cu")
		(net "GND")
	)
	(via
		(at 50.145442 -152.779984)
		(size 0.508)
		(drill 0.254)
		(layers "F.Cu" "B.Cu")
		(net "GND")
	)
	(via
		(at 214.615014 -196.466714)
		(size 0.4572)
		(drill 0.2032)
		(layers "F.Cu" "B.Cu")
		(net "GND")
	)
	(via
		(at 339.575902 -84.933536)
		(size 0.508)
		(drill 0.254)
		(layers "F.Cu" "B.Cu")
		(net "GND")
	)
	(via
		(at 383.545334 -228.45903)
		(size 0.4572)
		(drill 0.2032)
		(layers "F.Cu" "B.Cu")
		(net "GND")
	)
	(via
		(at 455.011282 -238.116618)
		(size 0.4572)
		(drill 0.2032)
		(layers "F.Cu" "B.Cu")
		(net "GND")
	)
	(via
		(at 120.208548 -281.59202)
		(size 0.4572)
		(drill 0.2032)
		(layers "F.Cu" "B.Cu")
		(net "GND")
	)
	(via
		(at 412.18358 -167.071548)
		(size 0.508)
		(drill 0.254)
		(layers "F.Cu" "B.Cu")
		(net "GND")
	)
	(via
		(at 73.1012 -15.255748)
		(size 0.508)
		(drill 0.254)
		(layers "F.Cu" "B.Cu")
		(net "GND")
	)
	(via
		(at 219.325952 -44.788328)
		(size 0.508)
		(drill 0.254)
		(layers "F.Cu" "B.Cu")
		(net "GND")
	)
	(via
		(at 447.467482 -249.166634)
		(size 0.4572)
		(drill 0.2032)
		(layers "F.Cu" "B.Cu")
		(net "GND")
	)
	(via
		(at 301.117 -25.7556)
		(size 0.508)
		(drill 0.254)
		(layers "F.Cu" "B.Cu")
		(net "GND")
	)
	(via
		(at 407.858214 -268.71676)
		(size 0.4572)
		(drill 0.2032)
		(layers "F.Cu" "B.Cu")
		(net "GND")
	)
	(via
		(at 229.59822 -55.132986)
		(size 0.508)
		(drill 0.254)
		(layers "F.Cu" "B.Cu")
		(net "GND")
	)
	(via
		(at 274.163282 -244.066568)
		(size 0.4572)
		(drill 0.2032)
		(layers "F.Cu" "B.Cu")
		(net "GND")
	)
	(via
		(at 65.25006 -426.54728)
		(size 0.4572)
		(drill 0.2032)
		(layers "F.Cu" "B.Cu")
		(net "GND")
	)
	(via
		(at 54.565296 -319.712594)
		(size 0.4572)
		(drill 0.2032)
		(layers "F.Cu" "B.Cu")
		(net "GND")
	)
	(via
		(at 382.135634 -229.272846)
		(size 0.4572)
		(drill 0.2032)
		(layers "F.Cu" "B.Cu")
		(net "GND")
	)
	(via
		(at 458.455014 -210.916774)
		(size 0.4572)
		(drill 0.2032)
		(layers "F.Cu" "B.Cu")
		(net "GND")
	)
	(via
		(at 18.679414 -233.86669)
		(size 0.4572)
		(drill 0.2032)
		(layers "F.Cu" "B.Cu")
		(net "GND")
	)
	(via
		(at 409.60421 -403.883876)
		(size 0.4064)
		(drill 0.2032)
		(layers "F.Cu" "B.Cu")
		(net "GND")
	)
	(via
		(at 62.176406 -320.063622)
		(size 0.4572)
		(drill 0.2032)
		(layers "F.Cu" "B.Cu")
		(net "GND")
	)
	(via
		(at 424.69816 -144.689068)
		(size 0.508)
		(drill 0.254)
		(layers "F.Cu" "B.Cu")
		(net "GND")
	)
	(via
		(at 2.764536 -91.870022)
		(size 0.508)
		(drill 0.254)
		(layers "F.Cu" "B.Cu")
		(net "GND")
	)
	(via
		(at 273.0754 -14.143228)
		(size 0.508)
		(drill 0.254)
		(layers "F.Cu" "B.Cu")
		(net "GND")
	)
	(via
		(at 442.133482 -247.466612)
		(size 0.4572)
		(drill 0.2032)
		(layers "F.Cu" "B.Cu")
		(net "GND")
	)
	(via
		(at 52.082446 -217.716608)
		(size 0.4572)
		(drill 0.2032)
		(layers "F.Cu" "B.Cu")
		(net "GND")
	)
	(via
		(at 28.433014 -308.666642)
		(size 0.4572)
		(drill 0.2032)
		(layers "F.Cu" "B.Cu")
		(net "GND")
	)
	(via
		(at 371.327934 -217.064336)
		(size 0.4572)
		(drill 0.2032)
		(layers "F.Cu" "B.Cu")
		(net "GND")
	)
	(via
		(at 405.648414 -260.21665)
		(size 0.4572)
		(drill 0.2032)
		(layers "F.Cu" "B.Cu")
		(net "GND")
	)
	(via
		(at 108.43387 -244.76329)
		(size 0.4572)
		(drill 0.2032)
		(layers "F.Cu" "B.Cu")
		(net "GND")
	)
	(via
		(at 404.462742 -406.370536)
		(size 0.4572)
		(drill 0.254)
		(layers "F.Cu" "B.Cu")
		(net "GND")
	)
	(via
		(at 339.84438 -237.411514)
		(size 0.4572)
		(drill 0.2032)
		(layers "F.Cu" "B.Cu")
		(net "GND")
	)
	(via
		(at 409.748482 -196.466714)
		(size 0.4572)
		(drill 0.2032)
		(layers "F.Cu" "B.Cu")
		(net "GND")
	)
	(via
		(at 58.608214 -250.866656)
		(size 0.4572)
		(drill 0.2032)
		(layers "F.Cu" "B.Cu")
		(net "GND")
	)
	(via
		(at 445.577214 -295.06672)
		(size 0.4572)
		(drill 0.2032)
		(layers "F.Cu" "B.Cu")
		(net "GND")
	)
	(via
		(at 341.834216 -265.314176)
		(size 0.4572)
		(drill 0.2032)
		(layers "F.Cu" "B.Cu")
		(net "GND")
	)
	(via
		(at 169.113962 -207.51673)
		(size 0.4572)
		(drill 0.2032)
		(layers "F.Cu" "B.Cu")
		(net "GND")
	)
	(via
		(at 120.568212 -230.086662)
		(size 0.4572)
		(drill 0.2032)
		(layers "F.Cu" "B.Cu")
		(net "GND")
	)
	(via
		(at 471.03538 -59.024266)
		(size 0.508)
		(drill 0.254)
		(layers "F.Cu" "B.Cu")
		(net "GND")
	)
	(via
		(at 361.569762 -262.058658)
		(size 0.4572)
		(drill 0.2032)
		(layers "F.Cu" "B.Cu")
		(net "GND")
	)
	(via
		(at 306.629054 -221.255336)
		(size 0.4572)
		(drill 0.2032)
		(layers "F.Cu" "B.Cu")
		(net "GND")
	)
	(via
		(at 336.195162 -262.058658)
		(size 0.4572)
		(drill 0.2032)
		(layers "F.Cu" "B.Cu")
		(net "GND")
	)
	(via
		(at 416.554412 -18.491454)
		(size 0.508)
		(drill 0.254)
		(layers "F.Cu" "B.Cu")
		(net "GND")
	)
	(via
		(at 226.622356 -36.040314)
		(size 0.508)
		(drill 0.254)
		(layers "F.Cu" "B.Cu")
		(net "GND")
	)
	(via
		(at 199.527414 -261.066788)
		(size 0.4572)
		(drill 0.2032)
		(layers "F.Cu" "B.Cu")
		(net "GND")
	)
	(via
		(at 378.486162 -278.336502)
		(size 0.4572)
		(drill 0.2032)
		(layers "F.Cu" "B.Cu")
		(net "GND")
	)
	(via
		(at 395.37005 -403.883876)
		(size 0.4064)
		(drill 0.2032)
		(layers "F.Cu" "B.Cu")
		(net "GND")
	)
	(via
		(at 348.882462 -269.38351)
		(size 0.4572)
		(drill 0.2032)
		(layers "F.Cu" "B.Cu")
		(net "GND")
	)
	(via
		(at 434.589682 -291.666676)
		(size 0.4572)
		(drill 0.2032)
		(layers "F.Cu" "B.Cu")
		(net "GND")
	)
	(via
		(at 80.25003 -430.299622)
		(size 0.4572)
		(drill 0.2032)
		(layers "F.Cu" "B.Cu")
		(net "GND")
	)
	(via
		(at 414.110678 -400.200368)
		(size 0.4572)
		(drill 0.254)
		(layers "F.Cu" "B.Cu")
		(net "GND")
	)
	(via
		(at 207.071214 -294.216582)
		(size 0.4572)
		(drill 0.2032)
		(layers "F.Cu" "B.Cu")
		(net "GND")
	)
	(via
		(at 177.75555 -115.775486)
		(size 0.4572)
		(drill 0.254)
		(layers "F.Cu" "B.Cu")
		(net "GND")
	)
	(via
		(at 71.250048 -435.0512)
		(size 0.4572)
		(drill 0.2032)
		(layers "F.Cu" "B.Cu")
		(net "GND")
	)
	(via
		(at 467.08314 -47.186088)
		(size 0.508)
		(drill 0.254)
		(layers "F.Cu" "B.Cu")
		(net "GND")
	)
	(via
		(at 372.847616 -279.964134)
		(size 0.4572)
		(drill 0.2032)
		(layers "F.Cu" "B.Cu")
		(net "GND")
	)
	(via
		(at 22.620732 -0.76454)
		(size 0.508)
		(drill 0.254)
		(layers "F.Cu" "B.Cu")
		(net "GND")
	)
	(via
		(at 270.063214 -223.666558)
		(size 0.4572)
		(drill 0.2032)
		(layers "F.Cu" "B.Cu")
		(net "GND")
	)
	(via
		(at 287.745424 -13.443204)
		(size 0.508)
		(drill 0.254)
		(layers "F.Cu" "B.Cu")
		(net "GND")
	)
	(via
		(at 71.250048 -427.851316)
		(size 0.4572)
		(drill 0.2032)
		(layers "F.Cu" "B.Cu")
		(net "GND")
	)
	(via
		(at 411.958282 -261.066788)
		(size 0.4572)
		(drill 0.2032)
		(layers "F.Cu" "B.Cu")
		(net "GND")
	)
	(via
		(at 370.38788 -243.108988)
		(size 0.4572)
		(drill 0.2032)
		(layers "F.Cu" "B.Cu")
		(net "GND")
	)
	(via
		(at 464.764882 -200.716642)
		(size 0.4572)
		(drill 0.2032)
		(layers "F.Cu" "B.Cu")
		(net "GND")
	)
	(via
		(at 396.71625 -410.030168)
		(size 0.4064)
		(drill 0.2032)
		(layers "F.Cu" "B.Cu")
		(net "GND")
	)
	(via
		(at 377.333256 -339.114638)
		(size 0.49022)
		(drill 0.254)
		(layers "F.Cu" "B.Cu")
		(net "GND")
	)
	(via
		(at 365.219234 -216.25052)
		(size 0.4572)
		(drill 0.2032)
		(layers "F.Cu" "B.Cu")
		(net "GND")
	)
	(via
		(at 195.427346 -267.016738)
		(size 0.4572)
		(drill 0.2032)
		(layers "F.Cu" "B.Cu")
		(net "GND")
	)
	(via
		(at 66.152014 -303.566576)
		(size 0.4572)
		(drill 0.2032)
		(layers "F.Cu" "B.Cu")
		(net "GND")
	)
	(via
		(at 419.502082 -288.266632)
		(size 0.4572)
		(drill 0.2032)
		(layers "F.Cu" "B.Cu")
		(net "GND")
	)
	(via
		(at 51.622198 -173.113446)
		(size 0.49022)
		(drill 0.254)
		(layers "F.Cu" "B.Cu")
		(net "GND")
	)
	(via
		(at 356.761034 -222.761556)
		(size 0.4572)
		(drill 0.2032)
		(layers "F.Cu" "B.Cu")
		(net "GND")
	)
	(via
		(at 9.245346 -229.616762)
		(size 0.4572)
		(drill 0.2032)
		(layers "F.Cu" "B.Cu")
		(net "GND")
	)
	(via
		(at 187.883546 -313.766708)
		(size 0.4572)
		(drill 0.2032)
		(layers "F.Cu" "B.Cu")
		(net "GND")
	)
	(via
		(at 175.005746 -203.266802)
		(size 0.4572)
		(drill 0.2032)
		(layers "F.Cu" "B.Cu")
		(net "GND")
	)
	(via
		(at 410.35732 -167.731948)
		(size 0.508)
		(drill 0.254)
		(layers "F.Cu" "B.Cu")
		(net "GND")
	)
	(via
		(at 383.478278 -404.51786)
		(size 0.4572)
		(drill 0.254)
		(layers "F.Cu" "B.Cu")
		(net "GND")
	)
	(via
		(at 182.549546 -268.71676)
		(size 0.4572)
		(drill 0.2032)
		(layers "F.Cu" "B.Cu")
		(net "GND")
	)
	(via
		(at 139.964414 -342.557354)
		(size 0.49022)
		(drill 0.254)
		(layers "F.Cu" "B.Cu")
		(net "GND")
	)
	(via
		(at 276.373082 -284.866588)
		(size 0.4572)
		(drill 0.2032)
		(layers "F.Cu" "B.Cu")
		(net "GND")
	)
	(via
		(at 421.618156 -182.290974)
		(size 0.508)
		(drill 0.254)
		(layers "F.Cu" "B.Cu")
		(net "GND")
	)
	(via
		(at 139.595606 -401.492212)
		(size 0.4572)
		(drill 0.254)
		(layers "F.Cu" "B.Cu")
		(net "GND")
	)
	(via
		(at 63.250064 -432.747166)
		(size 0.4572)
		(drill 0.2032)
		(layers "F.Cu" "B.Cu")
		(net "GND")
	)
	(via
		(at 336.250026 -437.49976)
		(size 0.4572)
		(drill 0.2032)
		(layers "F.Cu" "B.Cu")
		(net "GND")
	)
	(via
		(at 336.195162 -279.964134)
		(size 0.4572)
		(drill 0.2032)
		(layers "F.Cu" "B.Cu")
		(net "GND")
	)
	(via
		(at 419.348412 -16.967454)
		(size 0.508)
		(drill 0.254)
		(layers "F.Cu" "B.Cu")
		(net "GND")
	)
	(via
		(at 46.964346 -244.916706)
		(size 0.4572)
		(drill 0.2032)
		(layers "F.Cu" "B.Cu")
		(net "GND")
	)
	(via
		(at 427.045882 -261.066788)
		(size 0.4572)
		(drill 0.2032)
		(layers "F.Cu" "B.Cu")
		(net "GND")
	)
	(via
		(at 50.38725 -407.638504)
		(size 0.4572)
		(drill 0.254)
		(layers "F.Cu" "B.Cu")
		(net "GND")
	)
	(via
		(at 130.076194 -284.033722)
		(size 0.4572)
		(drill 0.2032)
		(layers "F.Cu" "B.Cu")
		(net "GND")
	)
	(via
		(at 59.842146 -295.06672)
		(size 0.4572)
		(drill 0.2032)
		(layers "F.Cu" "B.Cu")
		(net "GND")
	)
	(via
		(at 340.894416 -286.475424)
		(size 0.4572)
		(drill 0.2032)
		(layers "F.Cu" "B.Cu")
		(net "GND")
	)
	(via
		(at 324.76694 -407.638504)
		(size 0.4572)
		(drill 0.254)
		(layers "F.Cu" "B.Cu")
		(net "GND")
	)
	(via
		(at 132.315966 -216.25052)
		(size 0.4572)
		(drill 0.2032)
		(layers "F.Cu" "B.Cu")
		(net "GND")
	)
	(via
		(at 427.229016 -134.89051)
		(size 0.508)
		(drill 0.254)
		(layers "F.Cu" "B.Cu")
		(net "GND")
	)
	(via
		(at 159.918146 -251.716794)
		(size 0.4572)
		(drill 0.2032)
		(layers "F.Cu" "B.Cu")
		(net "GND")
	)
	(via
		(at 431.066448 -17.601438)
		(size 0.508)
		(drill 0.254)
		(layers "F.Cu" "B.Cu")
		(net "GND")
	)
	(via
		(at 58.608214 -284.866588)
		(size 0.4572)
		(drill 0.2032)
		(layers "F.Cu" "B.Cu")
		(net "GND")
	)
	(via
		(at 124.279406 -404.51786)
		(size 0.4572)
		(drill 0.254)
		(layers "F.Cu" "B.Cu")
		(net "GND")
	)
	(via
		(at 386.004562 -278.336502)
		(size 0.4572)
		(drill 0.2032)
		(layers "F.Cu" "B.Cu")
		(net "GND")
	)
	(via
		(at 180.339746 -195.616576)
		(size 0.4572)
		(drill 0.2032)
		(layers "F.Cu" "B.Cu")
		(net "GND")
	)
	(via
		(at 197.637146 -296.766742)
		(size 0.4572)
		(drill 0.2032)
		(layers "F.Cu" "B.Cu")
		(net "GND")
	)
	(via
		(at 462.555082 -233.86669)
		(size 0.4572)
		(drill 0.2032)
		(layers "F.Cu" "B.Cu")
		(net "GND")
	)
	(via
		(at 345.593416 -278.336502)
		(size 0.4572)
		(drill 0.2032)
		(layers "F.Cu" "B.Cu")
		(net "GND")
	)
	(via
		(at 135.714994 -256.361438)
		(size 0.4572)
		(drill 0.2032)
		(layers "F.Cu" "B.Cu")
		(net "GND")
	)
	(via
		(at 156.258006 -407.638504)
		(size 0.4572)
		(drill 0.254)
		(layers "F.Cu" "B.Cu")
		(net "GND")
	)
	(via
		(at 420.671752 -354.262944)
		(size 0.508)
		(drill 0.254)
		(layers "F.Cu" "B.Cu")
		(net "GND")
	)
	(via
		(at 439.923682 -210.066636)
		(size 0.4572)
		(drill 0.2032)
		(layers "F.Cu" "B.Cu")
		(net "GND")
	)
	(via
		(at 136.075166 -214.546434)
		(size 0.4572)
		(drill 0.2032)
		(layers "F.Cu" "B.Cu")
		(net "GND")
	)
	(via
		(at 118.798594 -271.011396)
		(size 0.4572)
		(drill 0.2032)
		(layers "F.Cu" "B.Cu")
		(net "GND")
	)
	(via
		(at 292.694614 -270.416782)
		(size 0.4572)
		(drill 0.2032)
		(layers "F.Cu" "B.Cu")
		(net "GND")
	)
	(via
		(at 266.619482 -211.766658)
		(size 0.4572)
		(drill 0.2032)
		(layers "F.Cu" "B.Cu")
		(net "GND")
	)
	(via
		(at 150.21433 -33.564068)
		(size 0.508)
		(drill 0.254)
		(layers "F.Cu" "B.Cu")
		(net "GND")
	)
	(via
		(at 171.562014 -303.566576)
		(size 0.4572)
		(drill 0.2032)
		(layers "F.Cu" "B.Cu")
		(net "GND")
	)
	(via
		(at 355.6 -414.111948)
		(size 0.508)
		(drill 0.254)
		(layers "F.Cu" "B.Cu")
		(net "GND")
	)
	(via
		(at 254.975614 -296.766742)
		(size 0.4572)
		(drill 0.2032)
		(layers "F.Cu" "B.Cu")
		(net "GND")
	)
	(via
		(at 95.077026 -406.370536)
		(size 0.4572)
		(drill 0.254)
		(layers "F.Cu" "B.Cu")
		(net "GND")
	)
	(via
		(at 457.248006 -68.471034)
		(size 0.508)
		(drill 0.254)
		(layers "F.Cu" "B.Cu")
		(net "GND")
	)
	(via
		(at 415.402014 -315.46673)
		(size 0.4572)
		(drill 0.2032)
		(layers "F.Cu" "B.Cu")
		(net "GND")
	)
	(via
		(at 405.648414 -258.516628)
		(size 0.4572)
		(drill 0.2032)
		(layers "F.Cu" "B.Cu")
		(net "GND")
	)
	(via
		(at 62.051946 -234.716574)
		(size 0.4572)
		(drill 0.2032)
		(layers "F.Cu" "B.Cu")
		(net "GND")
	)
	(via
		(at 430.489614 -212.616796)
		(size 0.4572)
		(drill 0.2032)
		(layers "F.Cu" "B.Cu")
		(net "GND")
	)
	(via
		(at 130.350006 -431.451258)
		(size 0.4572)
		(drill 0.2032)
		(layers "F.Cu" "B.Cu")
		(net "GND")
	)
	(via
		(at 140.349986 -438.499758)
		(size 0.4572)
		(drill 0.2032)
		(layers "F.Cu" "B.Cu")
		(net "GND")
	)
	(via
		(at 337.210654 -137.172446)
		(size 0.508)
		(drill 0.254)
		(layers "F.Cu" "B.Cu")
		(net "GND")
	)
	(via
		(at 187.883546 -270.416782)
		(size 0.4572)
		(drill 0.2032)
		(layers "F.Cu" "B.Cu")
		(net "GND")
	)
	(via
		(at 131.015994 -274.266914)
		(size 0.4572)
		(drill 0.2032)
		(layers "F.Cu" "B.Cu")
		(net "GND")
	)
	(via
		(at 58.608214 -271.266666)
		(size 0.4572)
		(drill 0.2032)
		(layers "F.Cu" "B.Cu")
		(net "GND")
	)
	(via
		(at 460.664814 -238.966756)
		(size 0.4572)
		(drill 0.2032)
		(layers "F.Cu" "B.Cu")
		(net "GND")
	)
	(via
		(at 178.289204 -48.299878)
		(size 0.508)
		(drill 0.254)
		(layers "F.Cu" "B.Cu")
		(net "GND")
	)
	(via
		(at 171.562014 -261.066788)
		(size 0.4572)
		(drill 0.2032)
		(layers "F.Cu" "B.Cu")
		(net "GND")
	)
	(via
		(at 108.262166 -326.836532)
		(size 0.508)
		(drill 0.254)
		(layers "F.Cu" "B.Cu")
		(net "GND")
	)
	(via
		(at 256.750312 -78.059788)
		(size 0.508)
		(drill 0.254)
		(layers "F.Cu" "B.Cu")
		(net "GND")
	)
	(via
		(at 54.508146 -304.416714)
		(size 0.4572)
		(drill 0.2032)
		(layers "F.Cu" "B.Cu")
		(net "GND")
	)
	(via
		(at 300.022514 -276.366732)
		(size 0.4572)
		(drill 0.2032)
		(layers "F.Cu" "B.Cu")
		(net "GND")
	)
	(via
		(at 2.764536 -122.350022)
		(size 0.508)
		(drill 0.254)
		(layers "F.Cu" "B.Cu")
		(net "GND")
	)
	(via
		(at 266.619482 -205.816708)
		(size 0.4572)
		(drill 0.2032)
		(layers "F.Cu" "B.Cu")
		(net "GND")
	)
	(via
		(at 37.210746 -278.066754)
		(size 0.4572)
		(drill 0.2032)
		(layers "F.Cu" "B.Cu")
		(net "GND")
	)
	(via
		(at 169.352214 -262.76681)
		(size 0.4572)
		(drill 0.2032)
		(layers "F.Cu" "B.Cu")
		(net "GND")
	)
	(via
		(at 65.388236 -105.637584)
		(size 0.508)
		(drill 0.254)
		(layers "F.Cu" "B.Cu")
		(net "GND")
	)
	(via
		(at 375.087134 -213.732618)
		(size 0.4572)
		(drill 0.2032)
		(layers "F.Cu" "B.Cu")
		(net "GND")
	)
	(via
		(at 354.411534 -226.831144)
		(size 0.4572)
		(drill 0.2032)
		(layers "F.Cu" "B.Cu")
		(net "GND")
	)
	(via
		(at 330.89342 -409.396184)
		(size 0.4572)
		(drill 0.254)
		(layers "F.Cu" "B.Cu")
		(net "GND")
	)
	(via
		(at 417.292282 -222.816674)
		(size 0.4572)
		(drill 0.2032)
		(layers "F.Cu" "B.Cu")
		(net "GND")
	)
	(via
		(at 187.883546 -204.96657)
		(size 0.4572)
		(drill 0.2032)
		(layers "F.Cu" "B.Cu")
		(net "GND")
	)
	(via
		(at 383.550922 -249.073924)
		(size 0.4572)
		(drill 0.2032)
		(layers "F.Cu" "B.Cu")
		(net "GND")
	)
	(via
		(at 457.221082 -204.116686)
		(size 0.4572)
		(drill 0.2032)
		(layers "F.Cu" "B.Cu")
		(net "GND")
	)
	(via
		(at 291.460682 -297.616626)
		(size 0.4572)
		(drill 0.2032)
		(layers "F.Cu" "B.Cu")
		(net "GND")
	)
	(via
		(at 422.945814 -261.916672)
		(size 0.4572)
		(drill 0.2032)
		(layers "F.Cu" "B.Cu")
		(net "GND")
	)
	(via
		(at 165.252146 -210.916774)
		(size 0.4572)
		(drill 0.2032)
		(layers "F.Cu" "B.Cu")
		(net "GND")
	)
	(via
		(at 387.800342 -400.224244)
		(size 0.4572)
		(drill 0.254)
		(layers "F.Cu" "B.Cu")
		(net "GND")
	)
	(via
		(at 26.223214 -213.46668)
		(size 0.4572)
		(drill 0.2032)
		(layers "F.Cu" "B.Cu")
		(net "GND")
	)
	(via
		(at 132.785866 -228.45903)
		(size 0.4572)
		(drill 0.2032)
		(layers "F.Cu" "B.Cu")
		(net "GND")
	)
	(via
		(at 381.673862 -401.492212)
		(size 0.4572)
		(drill 0.254)
		(layers "F.Cu" "B.Cu")
		(net "GND")
	)
	(via
		(at 108.025946 -329.10272)
		(size 0.508)
		(drill 0.254)
		(layers "F.Cu" "B.Cu")
		(net "GND")
	)
	(via
		(at 56.045608 -158.66745)
		(size 0.49022)
		(drill 0.254)
		(layers "F.Cu" "B.Cu")
		(net "GND")
	)
	(via
		(at 276.373082 -316.316614)
		(size 0.4572)
		(drill 0.2032)
		(layers "F.Cu" "B.Cu")
		(net "GND")
	)
	(via
		(at 335.725008 -275.8948)
		(size 0.4572)
		(drill 0.2032)
		(layers "F.Cu" "B.Cu")
		(net "GND")
	)
	(via
		(at 445.577214 -229.616762)
		(size 0.4572)
		(drill 0.2032)
		(layers "F.Cu" "B.Cu")
		(net "GND")
	)
	(via
		(at 384.595116 -257.98907)
		(size 0.4572)
		(drill 0.2032)
		(layers "F.Cu" "B.Cu")
		(net "GND")
	)
	(via
		(at 417.292282 -245.76659)
		(size 0.4572)
		(drill 0.2032)
		(layers "F.Cu" "B.Cu")
		(net "GND")
	)
	(via
		(at 407.34996 -435.0512)
		(size 0.4572)
		(drill 0.2032)
		(layers "F.Cu" "B.Cu")
		(net "GND")
	)
	(via
		(at 51.064414 -286.56661)
		(size 0.4572)
		(drill 0.2032)
		(layers "F.Cu" "B.Cu")
		(net "GND")
	)
	(via
		(at 11.135614 -262.76681)
		(size 0.4572)
		(drill 0.2032)
		(layers "F.Cu" "B.Cu")
		(net "GND")
	)
	(via
		(at 336.55508 -244.73662)
		(size 0.4572)
		(drill 0.2032)
		(layers "F.Cu" "B.Cu")
		(net "GND")
	)
	(via
		(at 9.245346 -223.666558)
		(size 0.4572)
		(drill 0.2032)
		(layers "F.Cu" "B.Cu")
		(net "GND")
	)
	(via
		(at 266.619482 -241.516662)
		(size 0.4572)
		(drill 0.2032)
		(layers "F.Cu" "B.Cu")
		(net "GND")
	)
	(via
		(at 147.349972 -426.69968)
		(size 0.4572)
		(drill 0.2032)
		(layers "F.Cu" "B.Cu")
		(net "GND")
	)
	(via
		(at 136.075166 -230.900478)
		(size 0.4572)
		(drill 0.2032)
		(layers "F.Cu" "B.Cu")
		(net "GND")
	)
	(via
		(at 361.569762 -286.475424)
		(size 0.4572)
		(drill 0.2032)
		(layers "F.Cu" "B.Cu")
		(net "GND")
	)
	(via
		(at 417.292282 -215.166702)
		(size 0.4572)
		(drill 0.2032)
		(layers "F.Cu" "B.Cu")
		(net "GND")
	)
	(via
		(at 312.875168 -410.030168)
		(size 0.4064)
		(drill 0.2032)
		(layers "F.Cu" "B.Cu")
		(net "GND")
	)
	(via
		(at 212.724746 -251.716794)
		(size 0.4572)
		(drill 0.2032)
		(layers "F.Cu" "B.Cu")
		(net "GND")
	)
	(via
		(at 422.945814 -203.266802)
		(size 0.4572)
		(drill 0.2032)
		(layers "F.Cu" "B.Cu")
		(net "GND")
	)
	(via
		(at 458.455014 -233.016806)
		(size 0.4572)
		(drill 0.2032)
		(layers "F.Cu" "B.Cu")
		(net "GND")
	)
	(via
		(at 186.649614 -314.616592)
		(size 0.4572)
		(drill 0.2032)
		(layers "F.Cu" "B.Cu")
		(net "GND")
	)
	(via
		(at 370.968016 -279.964134)
		(size 0.4572)
		(drill 0.2032)
		(layers "F.Cu" "B.Cu")
		(net "GND")
	)
	(via
		(at 306.484528 -403.883876)
		(size 0.4064)
		(drill 0.2032)
		(layers "F.Cu" "B.Cu")
		(net "GND")
	)
	(via
		(at 47.150782 -352.304858)
		(size 0.508)
		(drill 0.254)
		(layers "F.Cu" "B.Cu")
		(net "GND")
	)
	(via
		(at 419.778942 -406.370536)
		(size 0.4572)
		(drill 0.254)
		(layers "F.Cu" "B.Cu")
		(net "GND")
	)
	(via
		(at 314.092082 -250.866656)
		(size 0.4572)
		(drill 0.2032)
		(layers "F.Cu" "B.Cu")
		(net "GND")
	)
	(via
		(at 153.34996 -436.051198)
		(size 0.4572)
		(drill 0.2032)
		(layers "F.Cu" "B.Cu")
		(net "GND")
	)
	(via
		(at 202.971146 -234.716574)
		(size 0.4572)
		(drill 0.2032)
		(layers "F.Cu" "B.Cu")
		(net "GND")
	)
	(via
		(at 373.787162 -262.058658)
		(size 0.4572)
		(drill 0.2032)
		(layers "F.Cu" "B.Cu")
		(net "GND")
	)
	(via
		(at 181.89956 -419.07333)
		(size 0.508)
		(drill 0.254)
		(layers "F.Cu" "B.Cu")
		(net "GND")
	)
	(via
		(at 424.836082 -224.516696)
		(size 0.4572)
		(drill 0.2032)
		(layers "F.Cu" "B.Cu")
		(net "GND")
	)
	(via
		(at 307.782214 -298.466764)
		(size 0.4572)
		(drill 0.2032)
		(layers "F.Cu" "B.Cu")
		(net "GND")
	)
	(via
		(at 49.40681 -148.191982)
		(size 0.508)
		(drill 0.254)
		(layers "F.Cu" "B.Cu")
		(net "GND")
	)
	(via
		(at 58.666888 -9.424924)
		(size 0.508)
		(drill 0.254)
		(layers "F.Cu" "B.Cu")
		(net "GND")
	)
	(via
		(at 41.63568 -386.20954)
		(size 0.508)
		(drill 0.254)
		(layers "F.Cu" "B.Cu")
		(net "GND")
	)
	(via
		(at 337.495134 -217.064336)
		(size 0.4572)
		(drill 0.2032)
		(layers "F.Cu" "B.Cu")
		(net "GND")
	)
	(via
		(at 342.304116 -271.011396)
		(size 0.4572)
		(drill 0.2032)
		(layers "F.Cu" "B.Cu")
		(net "GND")
	)
	(via
		(at 135.714994 -254.733552)
		(size 0.4572)
		(drill 0.2032)
		(layers "F.Cu" "B.Cu")
		(net "GND")
	)
	(via
		(at 129.136394 -271.011396)
		(size 0.4572)
		(drill 0.2032)
		(layers "F.Cu" "B.Cu")
		(net "GND")
	)
	(via
		(at 93.784166 -227.64496)
		(size 0.4572)
		(drill 0.2032)
		(layers "F.Cu" "B.Cu")
		(net "GND")
	)
	(via
		(at 432.379882 -291.666676)
		(size 0.4572)
		(drill 0.2032)
		(layers "F.Cu" "B.Cu")
		(net "GND")
	)
	(via
		(at 427.045882 -207.51673)
		(size 0.4572)
		(drill 0.2032)
		(layers "F.Cu" "B.Cu")
		(net "GND")
	)
	(via
		(at 425.207684 -361.726734)
		(size 0.49022)
		(drill 0.254)
		(layers "F.Cu" "B.Cu")
		(net "GND")
	)
	(via
		(at 302.448214 -250.016772)
		(size 0.4572)
		(drill 0.2032)
		(layers "F.Cu" "B.Cu")
		(net "GND")
	)
	(via
		(at 135.605266 -246.364506)
		(size 0.4572)
		(drill 0.2032)
		(layers "F.Cu" "B.Cu")
		(net "GND")
	)
	(via
		(at 434.02504 -121.419874)
		(size 0.508)
		(drill 0.254)
		(layers "F.Cu" "B.Cu")
		(net "GND")
	)
	(via
		(at 172.795946 -258.516628)
		(size 0.4572)
		(drill 0.2032)
		(layers "F.Cu" "B.Cu")
		(net "GND")
	)
	(via
		(at 315.250068 -430.299622)
		(size 0.4572)
		(drill 0.2032)
		(layers "F.Cu" "B.Cu")
		(net "GND")
	)
	(via
		(at 293.757096 -360.833924)
		(size 0.508)
		(drill 0.254)
		(layers "F.Cu" "B.Cu")
		(net "GND")
	)
	(via
		(at 335.900776 -337.692238)
		(size 0.49022)
		(drill 0.254)
		(layers "F.Cu" "B.Cu")
		(net "GND")
	)
	(via
		(at 373.787416 -268.569694)
		(size 0.4572)
		(drill 0.2032)
		(layers "F.Cu" "B.Cu")
		(net "GND")
	)
	(via
		(at 89.554812 -239.853216)
		(size 0.4572)
		(drill 0.2032)
		(layers "F.Cu" "B.Cu")
		(net "GND")
	)
	(via
		(at 101.302566 -240.667286)
		(size 0.4572)
		(drill 0.2032)
		(layers "F.Cu" "B.Cu")
		(net "GND")
	)
	(via
		(at 190.093346 -261.916672)
		(size 0.4572)
		(drill 0.2032)
		(layers "F.Cu" "B.Cu")
		(net "GND")
	)
	(via
		(at 378.016516 -279.150318)
		(size 0.4572)
		(drill 0.2032)
		(layers "F.Cu" "B.Cu")
		(net "GND")
	)
	(via
		(at 441.308236 -101.34346)
		(size 0.508)
		(drill 0.254)
		(layers "F.Cu" "B.Cu")
		(net "GND")
	)
	(via
		(at 49.917604 -144.22755)
		(size 0.508)
		(drill 0.254)
		(layers "F.Cu" "B.Cu")
		(net "GND")
	)
	(via
		(at 123.497594 -267.755878)
		(size 0.4572)
		(drill 0.2032)
		(layers "F.Cu" "B.Cu")
		(net "GND")
	)
	(via
		(at 344.07348 -238.225584)
		(size 0.4572)
		(drill 0.2032)
		(layers "F.Cu" "B.Cu")
		(net "GND")
	)
	(via
		(at 159.918146 -307.816758)
		(size 0.4572)
		(drill 0.2032)
		(layers "F.Cu" "B.Cu")
		(net "GND")
	)
	(via
		(at 394.899642 -50.89525)
		(size 0.508)
		(drill 0.254)
		(layers "F.Cu" "B.Cu")
		(net "GND")
	)
	(via
		(at 336.55508 -234.970066)
		(size 0.4572)
		(drill 0.2032)
		(layers "F.Cu" "B.Cu")
		(net "GND")
	)
	(via
		(at 376.606562 -286.475424)
		(size 0.4572)
		(drill 0.2032)
		(layers "F.Cu" "B.Cu")
		(net "GND")
	)
	(via
		(at 267.260832 -439.905394)
		(size 0.508)
		(drill 0.254)
		(layers "F.Cu" "B.Cu")
		(net "GND")
	)
	(via
		(at 58.608214 -233.86669)
		(size 0.4572)
		(drill 0.2032)
		(layers "F.Cu" "B.Cu")
		(net "GND")
	)
	(via
		(at 92.844366 -242.294918)
		(size 0.4572)
		(drill 0.2032)
		(layers "F.Cu" "B.Cu")
		(net "GND")
	)
	(via
		(at 361.460034 -248.806208)
		(size 0.4572)
		(drill 0.2032)
		(layers "F.Cu" "B.Cu")
		(net "GND")
	)
	(via
		(at 57.11063 -4.962652)
		(size 0.508)
		(drill 0.254)
		(layers "F.Cu" "B.Cu")
		(net "GND")
	)
	(via
		(at 377.90628 -234.970066)
		(size 0.4572)
		(drill 0.2032)
		(layers "F.Cu" "B.Cu")
		(net "GND")
	)
	(via
		(at 325.15429 -341.020908)
		(size 0.508)
		(drill 0.254)
		(layers "F.Cu" "B.Cu")
		(net "GND")
	)
	(via
		(at 443.367414 -285.716726)
		(size 0.4572)
		(drill 0.2032)
		(layers "F.Cu" "B.Cu")
		(net "GND")
	)
	(via
		(at 342.735154 -40.461692)
		(size 0.4572)
		(drill 0.2032)
		(layers "F.Cu" "B.Cu")
		(net "GND")
	)
	(via
		(at 281.707082 -269.566644)
		(size 0.4572)
		(drill 0.2032)
		(layers "F.Cu" "B.Cu")
		(net "GND")
	)
	(via
		(at 379.426216 -278.336502)
		(size 0.4572)
		(drill 0.2032)
		(layers "F.Cu" "B.Cu")
		(net "GND")
	)
	(via
		(at 141.02588 -42.655998)
		(size 0.508)
		(drill 0.254)
		(layers "F.Cu" "B.Cu")
		(net "GND")
	)
	(via
		(at 342.161368 -400.858228)
		(size 0.4064)
		(drill 0.2032)
		(layers "F.Cu" "B.Cu")
		(net "GND")
	)
	(via
		(at 434.589682 -295.916604)
		(size 0.4572)
		(drill 0.2032)
		(layers "F.Cu" "B.Cu")
		(net "GND")
	)
	(via
		(at 126.786894 -255.547622)
		(size 0.4572)
		(drill 0.2032)
		(layers "F.Cu" "B.Cu")
		(net "GND")
	)
	(via
		(at 409.748482 -233.86669)
		(size 0.4572)
		(drill 0.2032)
		(layers "F.Cu" "B.Cu")
		(net "GND")
	)
	(via
		(at 99.161854 -333.356458)
		(size 0.49022)
		(drill 0.254)
		(layers "F.Cu" "B.Cu")
		(net "GND")
	)
	(via
		(at 349.731076 -401.492212)
		(size 0.4572)
		(drill 0.254)
		(layers "F.Cu" "B.Cu")
		(net "GND")
	)
	(via
		(at 136.075166 -245.55069)
		(size 0.4572)
		(drill 0.2032)
		(layers "F.Cu" "B.Cu")
		(net "GND")
	)
	(via
		(at 306.845716 -401.492212)
		(size 0.4572)
		(drill 0.254)
		(layers "F.Cu" "B.Cu")
		(net "GND")
	)
	(via
		(at 314.092082 -314.616592)
		(size 0.4572)
		(drill 0.2032)
		(layers "F.Cu" "B.Cu")
		(net "GND")
	)
	(via
		(at 207.071214 -261.066788)
		(size 0.4572)
		(drill 0.2032)
		(layers "F.Cu" "B.Cu")
		(net "GND")
	)
	(via
		(at 370.967762 -258.80314)
		(size 0.4572)
		(drill 0.2032)
		(layers "F.Cu" "B.Cu")
		(net "GND")
	)
	(via
		(at 14.014958 -335.871312)
		(size 0.508)
		(drill 0.254)
		(layers "F.Cu" "B.Cu")
		(net "GND")
	)
	(via
		(at 283.916882 -291.666676)
		(size 0.4572)
		(drill 0.2032)
		(layers "F.Cu" "B.Cu")
		(net "GND")
	)
	(via
		(at 214.615014 -316.316614)
		(size 0.4572)
		(drill 0.2032)
		(layers "F.Cu" "B.Cu")
		(net "GND")
	)
	(via
		(at 369.91798 -227.64496)
		(size 0.4572)
		(drill 0.2032)
		(layers "F.Cu" "B.Cu")
		(net "GND")
	)
	(via
		(at 370.85778 -229.272846)
		(size 0.4572)
		(drill 0.2032)
		(layers "F.Cu" "B.Cu")
		(net "GND")
	)
	(via
		(at 413.192214 -195.616576)
		(size 0.4572)
		(drill 0.2032)
		(layers "F.Cu" "B.Cu")
		(net "GND")
	)
	(via
		(at 306.548282 -271.266666)
		(size 0.4572)
		(drill 0.2032)
		(layers "F.Cu" "B.Cu")
		(net "GND")
	)
	(via
		(at 373.677434 -216.25052)
		(size 0.4572)
		(drill 0.2032)
		(layers "F.Cu" "B.Cu")
		(net "GND")
	)
	(via
		(at 24.332946 -240.666778)
		(size 0.4572)
		(drill 0.2032)
		(layers "F.Cu" "B.Cu")
		(net "GND")
	)
	(via
		(at 352.062034 -234.15625)
		(size 0.4572)
		(drill 0.2032)
		(layers "F.Cu" "B.Cu")
		(net "GND")
	)
	(via
		(at 421.89146 -359.414572)
		(size 0.508)
		(drill 0.254)
		(layers "F.Cu" "B.Cu")
		(net "GND")
	)
	(via
		(at 82.250026 -433.747164)
		(size 0.4572)
		(drill 0.2032)
		(layers "F.Cu" "B.Cu")
		(net "GND")
	)
	(via
		(at 49.128426 -407.638504)
		(size 0.4572)
		(drill 0.254)
		(layers "F.Cu" "B.Cu")
		(net "GND")
	)
	(via
		(at 277.607014 -268.71676)
		(size 0.4572)
		(drill 0.2032)
		(layers "F.Cu" "B.Cu")
		(net "GND")
	)
	(via
		(at 194.39001 -124.170948)
		(size 0.508)
		(drill 0.254)
		(layers "F.Cu" "B.Cu")
		(net "GND")
	)
	(via
		(at 169.352214 -221.116652)
		(size 0.4572)
		(drill 0.2032)
		(layers "F.Cu" "B.Cu")
		(net "GND")
	)
	(via
		(at 126.207266 -233.34218)
		(size 0.4572)
		(drill 0.2032)
		(layers "F.Cu" "B.Cu")
		(net "GND")
	)
	(via
		(at 212.724746 -315.46673)
		(size 0.4572)
		(drill 0.2032)
		(layers "F.Cu" "B.Cu")
		(net "GND")
	)
	(via
		(at 92.954348 -258.80314)
		(size 0.4572)
		(drill 0.2032)
		(layers "F.Cu" "B.Cu")
		(net "GND")
	)
	(via
		(at 134.426706 -23.599394)
		(size 0.508)
		(drill 0.254)
		(layers "F.Cu" "B.Cu")
		(net "GND")
	)
	(via
		(at 35.976814 -312.91657)
		(size 0.4572)
		(drill 0.2032)
		(layers "F.Cu" "B.Cu")
		(net "GND")
	)
	(via
		(at 292.694614 -285.716726)
		(size 0.4572)
		(drill 0.2032)
		(layers "F.Cu" "B.Cu")
		(net "GND")
	)
	(via
		(at 306.3875 -409.396184)
		(size 0.4572)
		(drill 0.254)
		(layers "F.Cu" "B.Cu")
		(net "GND")
	)
	(via
		(at 296.794682 -303.566576)
		(size 0.4572)
		(drill 0.2032)
		(layers "F.Cu" "B.Cu")
		(net "GND")
	)
	(via
		(at 159.918146 -263.616694)
		(size 0.4572)
		(drill 0.2032)
		(layers "F.Cu" "B.Cu")
		(net "GND")
	)
	(via
		(at 155.349956 -430.299622)
		(size 0.4572)
		(drill 0.2032)
		(layers "F.Cu" "B.Cu")
		(net "GND")
	)
	(via
		(at 438.2516 -94.503748)
		(size 0.508)
		(drill 0.254)
		(layers "F.Cu" "B.Cu")
		(net "GND")
	)
	(via
		(at 195.427346 -281.466798)
		(size 0.4572)
		(drill 0.2032)
		(layers "F.Cu" "B.Cu")
		(net "GND")
	)
	(via
		(at 384.350006 -431.29962)
		(size 0.4572)
		(drill 0.2032)
		(layers "F.Cu" "B.Cu")
		(net "GND")
	)
	(via
		(at 194.193414 -226.216718)
		(size 0.4572)
		(drill 0.2032)
		(layers "F.Cu" "B.Cu")
		(net "GND")
	)
	(via
		(at 347.363034 -232.528364)
		(size 0.4572)
		(drill 0.2032)
		(layers "F.Cu" "B.Cu")
		(net "GND")
	)
	(via
		(at 44.754546 -290.816792)
		(size 0.4572)
		(drill 0.2032)
		(layers "F.Cu" "B.Cu")
		(net "GND")
	)
	(via
		(at 52.298346 -251.716794)
		(size 0.4572)
		(drill 0.2032)
		(layers "F.Cu" "B.Cu")
		(net "GND")
	)
	(via
		(at 455.33183 -383.901442)
		(size 0.508)
		(drill 0.254)
		(layers "F.Cu" "B.Cu")
		(net "GND")
	)
	(via
		(at 97.58934 -389.674608)
		(size 0.4572)
		(drill 0.254)
		(layers "F.Cu" "B.Cu")
		(net "GND")
	)
	(via
		(at 324.76694 -410.664152)
		(size 0.4572)
		(drill 0.254)
		(layers "F.Cu" "B.Cu")
		(net "GND")
	)
	(via
		(at 383.11709 -400.858228)
		(size 0.4064)
		(drill 0.2032)
		(layers "F.Cu" "B.Cu")
		(net "GND")
	)
	(via
		(at 413.192214 -267.016738)
		(size 0.4572)
		(drill 0.2032)
		(layers "F.Cu" "B.Cu")
		(net "GND")
	)
	(via
		(at 65.25006 -430.147222)
		(size 0.4572)
		(drill 0.2032)
		(layers "F.Cu" "B.Cu")
		(net "GND")
	)
	(via
		(at 66.152014 -297.616626)
		(size 0.4572)
		(drill 0.2032)
		(layers "F.Cu" "B.Cu")
		(net "GND")
	)
	(via
		(at 333.845662 -280.778204)
		(size 0.4318)
		(drill 0.2032)
		(layers "F.Cu" "B.Cu")
		(net "GND")
	)
	(via
		(at 302.448214 -240.666778)
		(size 0.4572)
		(drill 0.2032)
		(layers "F.Cu" "B.Cu")
		(net "GND")
	)
	(via
		(at 16.789146 -279.766776)
		(size 0.4572)
		(drill 0.2032)
		(layers "F.Cu" "B.Cu")
		(net "GND")
	)
	(via
		(at 276.373082 -207.51673)
		(size 0.4572)
		(drill 0.2032)
		(layers "F.Cu" "B.Cu")
		(net "GND")
	)
	(via
		(at 348.605602 -326.910192)
		(size 0.508)
		(drill 0.254)
		(layers "F.Cu" "B.Cu")
		(net "GND")
	)
	(via
		(at 447.449448 -178.802792)
		(size 0.508)
		(drill 0.254)
		(layers "F.Cu" "B.Cu")
		(net "GND")
	)
	(via
		(at 453.121014 -248.31675)
		(size 0.4572)
		(drill 0.2032)
		(layers "F.Cu" "B.Cu")
		(net "GND")
	)
	(via
		(at 32.947102 -12.37488)
		(size 0.508)
		(drill 0.254)
		(layers "F.Cu" "B.Cu")
		(net "GND")
	)
	(via
		(at 423.084752 -319.522856)
		(size 0.4572)
		(drill 0.2032)
		(layers "F.Cu" "B.Cu")
		(net "GND")
	)
	(via
		(at 120.97639 -253.193804)
		(size 0.4572)
		(drill 0.2032)
		(layers "F.Cu" "B.Cu")
		(net "GND")
	)
	(via
		(at 283.916882 -216.866724)
		(size 0.4572)
		(drill 0.2032)
		(layers "F.Cu" "B.Cu")
		(net "GND")
	)
	(via
		(at 49.402238 -400.858228)
		(size 0.4064)
		(drill 0.2032)
		(layers "F.Cu" "B.Cu")
		(net "GND")
	)
	(via
		(at 91.074748 -273.453098)
		(size 0.4572)
		(drill 0.2032)
		(layers "F.Cu" "B.Cu")
		(net "GND")
	)
	(via
		(at 48.854614 -277.216616)
		(size 0.4572)
		(drill 0.2032)
		(layers "F.Cu" "B.Cu")
		(net "GND")
	)
	(via
		(at 29.977334 -170.029886)
		(size 0.508)
		(drill 0.254)
		(layers "F.Cu" "B.Cu")
		(net "GND")
	)
	(via
		(at 212.0646 -74.539348)
		(size 0.508)
		(drill 0.254)
		(layers "F.Cu" "B.Cu")
		(net "GND")
	)
	(via
		(at 277.607014 -272.116804)
		(size 0.4572)
		(drill 0.2032)
		(layers "F.Cu" "B.Cu")
		(net "GND")
	)
	(via
		(at 257.185414 -231.316784)
		(size 0.4572)
		(drill 0.2032)
		(layers "F.Cu" "B.Cu")
		(net "GND")
	)
	(via
		(at 345.95308 -236.597952)
		(size 0.4572)
		(drill 0.2032)
		(layers "F.Cu" "B.Cu")
		(net "GND")
	)
	(via
		(at 432.379882 -232.166668)
		(size 0.4572)
		(drill 0.2032)
		(layers "F.Cu" "B.Cu")
		(net "GND")
	)
	(via
		(at 299.004482 -272.966688)
		(size 0.4572)
		(drill 0.2032)
		(layers "F.Cu" "B.Cu")
		(net "GND")
	)
	(via
		(at 109.10189 -12.544552)
		(size 0.508)
		(drill 0.254)
		(layers "F.Cu" "B.Cu")
		(net "GND")
	)
	(via
		(at 457.221082 -299.316648)
		(size 0.4572)
		(drill 0.2032)
		(layers "F.Cu" "B.Cu")
		(net "GND")
	)
	(via
		(at 14.579346 -197.316598)
		(size 0.4572)
		(drill 0.2032)
		(layers "F.Cu" "B.Cu")
		(net "GND")
	)
	(via
		(at 199.527414 -205.816708)
		(size 0.4572)
		(drill 0.2032)
		(layers "F.Cu" "B.Cu")
		(net "GND")
	)
	(via
		(at 122.447812 -243.108988)
		(size 0.4572)
		(drill 0.2032)
		(layers "F.Cu" "B.Cu")
		(net "GND")
	)
	(via
		(at 138.424666 -217.064336)
		(size 0.4572)
		(drill 0.2032)
		(layers "F.Cu" "B.Cu")
		(net "GND")
	)
	(via
		(at 347.805248 -331.08392)
		(size 0.508)
		(drill 0.254)
		(layers "F.Cu" "B.Cu")
		(net "GND")
	)
	(via
		(at 184.439814 -239.81664)
		(size 0.4572)
		(drill 0.2032)
		(layers "F.Cu" "B.Cu")
		(net "GND")
	)
	(via
		(at 424.836082 -219.41663)
		(size 0.4572)
		(drill 0.2032)
		(layers "F.Cu" "B.Cu")
		(net "GND")
	)
	(via
		(at 161.808414 -215.166702)
		(size 0.4572)
		(drill 0.2032)
		(layers "F.Cu" "B.Cu")
		(net "GND")
	)
	(via
		(at 20.128484 -323.434456)
		(size 0.4572)
		(drill 0.2032)
		(layers "F.Cu" "B.Cu")
		(net "GND")
	)
	(via
		(at 438.033414 -258.516628)
		(size 0.4572)
		(drill 0.2032)
		(layers "F.Cu" "B.Cu")
		(net "GND")
	)
	(via
		(at 457.221082 -210.066636)
		(size 0.4572)
		(drill 0.2032)
		(layers "F.Cu" "B.Cu")
		(net "GND")
	)
	(via
		(at 266.619482 -267.866622)
		(size 0.4572)
		(drill 0.2032)
		(layers "F.Cu" "B.Cu")
		(net "GND")
	)
	(via
		(at 377.814332 -79.338424)
		(size 0.508)
		(drill 0.254)
		(layers "F.Cu" "B.Cu")
		(net "GND")
	)
	(via
		(at 115.433602 -252.221746)
		(size 0.4572)
		(drill 0.2032)
		(layers "F.Cu" "B.Cu")
		(net "GND")
	)
	(via
		(at 202.971146 -283.166566)
		(size 0.4572)
		(drill 0.2032)
		(layers "F.Cu" "B.Cu")
		(net "GND")
	)
	(via
		(at 85.90534 -253.10592)
		(size 0.4572)
		(drill 0.2032)
		(layers "F.Cu" "B.Cu")
		(net "GND")
	)
	(via
		(at 39.79799 -179.536344)
		(size 0.508)
		(drill 0.254)
		(layers "F.Cu" "B.Cu")
		(net "GND")
	)
	(via
		(at 394.84681 -12.37488)
		(size 0.508)
		(drill 0.254)
		(layers "F.Cu" "B.Cu")
		(net "GND")
	)
	(via
		(at 201.737214 -219.41663)
		(size 0.4572)
		(drill 0.2032)
		(layers "F.Cu" "B.Cu")
		(net "GND")
	)
	(via
		(at 432.379882 -275.516594)
		(size 0.4572)
		(drill 0.2032)
		(layers "F.Cu" "B.Cu")
		(net "GND")
	)
	(via
		(at 52.298346 -225.36658)
		(size 0.4572)
		(drill 0.2032)
		(layers "F.Cu" "B.Cu")
		(net "GND")
	)
	(via
		(at 332.697836 -407.638504)
		(size 0.4572)
		(drill 0.254)
		(layers "F.Cu" "B.Cu")
		(net "GND")
	)
	(via
		(at 41.310814 -267.866622)
		(size 0.4572)
		(drill 0.2032)
		(layers "F.Cu" "B.Cu")
		(net "GND")
	)
	(via
		(at 22.123146 -244.916706)
		(size 0.4572)
		(drill 0.2032)
		(layers "F.Cu" "B.Cu")
		(net "GND")
	)
	(via
		(at 89.555066 -247.992138)
		(size 0.4572)
		(drill 0.2032)
		(layers "F.Cu" "B.Cu")
		(net "GND")
	)
	(via
		(at 372.737634 -216.25052)
		(size 0.4572)
		(drill 0.2032)
		(layers "F.Cu" "B.Cu")
		(net "GND")
	)
	(via
		(at 457.221082 -314.616592)
		(size 0.4572)
		(drill 0.2032)
		(layers "F.Cu" "B.Cu")
		(net "GND")
	)
	(via
		(at 129.411222 -137.114026)
		(size 0.508)
		(drill 0.254)
		(layers "F.Cu" "B.Cu")
		(net "GND")
	)
	(via
		(at 412.393638 -410.664152)
		(size 0.4572)
		(drill 0.254)
		(layers "F.Cu" "B.Cu")
		(net "GND")
	)
	(via
		(at 11.135614 -216.866724)
		(size 0.4572)
		(drill 0.2032)
		(layers "F.Cu" "B.Cu")
		(net "GND")
	)
	(via
		(at 342.250014 -427.699678)
		(size 0.4572)
		(drill 0.2032)
		(layers "F.Cu" "B.Cu")
		(net "GND")
	)
	(via
		(at 87.226394 -95.342456)
		(size 0.508)
		(drill 0.254)
		(layers "F.Cu" "B.Cu")
		(net "GND")
	)
	(via
		(at 335.615534 -233.34218)
		(size 0.4572)
		(drill 0.2032)
		(layers "F.Cu" "B.Cu")
		(net "GND")
	)
	(via
		(at 160.221168 -204.96657)
		(size 0.4572)
		(drill 0.2032)
		(layers "F.Cu" "B.Cu")
		(net "GND")
	)
	(via
		(at 98.104706 -326.790812)
		(size 0.508)
		(drill 0.254)
		(layers "F.Cu" "B.Cu")
		(net "GND")
	)
	(via
		(at 411.349952 -438.651396)
		(size 0.4572)
		(drill 0.2032)
		(layers "F.Cu" "B.Cu")
		(net "GND")
	)
	(via
		(at 128.763522 -337.692238)
		(size 0.49022)
		(drill 0.254)
		(layers "F.Cu" "B.Cu")
		(net "GND")
	)
	(via
		(at 289.250882 -314.616592)
		(size 0.4572)
		(drill 0.2032)
		(layers "F.Cu" "B.Cu")
		(net "GND")
	)
	(via
		(at 187.883546 -285.716726)
		(size 0.4572)
		(drill 0.2032)
		(layers "F.Cu" "B.Cu")
		(net "GND")
	)
	(via
		(at 381.19558 -237.411514)
		(size 0.4572)
		(drill 0.2032)
		(layers "F.Cu" "B.Cu")
		(net "GND")
	)
	(via
		(at 285.150814 -263.616694)
		(size 0.4572)
		(drill 0.2032)
		(layers "F.Cu" "B.Cu")
		(net "GND")
	)
	(via
		(at 132.895594 -284.033722)
		(size 0.4572)
		(drill 0.2032)
		(layers "F.Cu" "B.Cu")
		(net "GND")
	)
	(via
		(at 212.84565 -53.356256)
		(size 0.508)
		(drill 0.254)
		(layers "F.Cu" "B.Cu")
		(net "GND")
	)
	(via
		(at 106.001566 -229.272846)
		(size 0.4572)
		(drill 0.2032)
		(layers "F.Cu" "B.Cu")
		(net "GND")
	)
	(via
		(at 126.786894 -265.314176)
		(size 0.4572)
		(drill 0.2032)
		(layers "F.Cu" "B.Cu")
		(net "GND")
	)
	(via
		(at 55.260494 -156.497274)
		(size 0.49022)
		(drill 0.254)
		(layers "F.Cu" "B.Cu")
		(net "GND")
	)
	(via
		(at 124.640594 -400.858228)
		(size 0.4064)
		(drill 0.2032)
		(layers "F.Cu" "B.Cu")
		(net "GND")
	)
	(via
		(at 128.133602 -339.114638)
		(size 0.49022)
		(drill 0.254)
		(layers "F.Cu" "B.Cu")
		(net "GND")
	)
	(via
		(at 424.836082 -230.466646)
		(size 0.4572)
		(drill 0.2032)
		(layers "F.Cu" "B.Cu")
		(net "GND")
	)
	(via
		(at 343.243662 -262.872474)
		(size 0.4572)
		(drill 0.2032)
		(layers "F.Cu" "B.Cu")
		(net "GND")
	)
	(via
		(at 195.427346 -229.616762)
		(size 0.4572)
		(drill 0.2032)
		(layers "F.Cu" "B.Cu")
		(net "GND")
	)
	(via
		(at 165.252146 -317.166752)
		(size 0.4572)
		(drill 0.2032)
		(layers "F.Cu" "B.Cu")
		(net "GND")
	)
	(via
		(at 458.455014 -276.366732)
		(size 0.4572)
		(drill 0.2032)
		(layers "F.Cu" "B.Cu")
		(net "GND")
	)
	(via
		(at 20.889214 -200.716642)
		(size 0.4572)
		(drill 0.2032)
		(layers "F.Cu" "B.Cu")
		(net "GND")
	)
	(via
		(at 56.83885 -163.761674)
		(size 0.49022)
		(drill 0.254)
		(layers "F.Cu" "B.Cu")
		(net "GND")
	)
	(via
		(at 343.603834 -219.506038)
		(size 0.4572)
		(drill 0.2032)
		(layers "F.Cu" "B.Cu")
		(net "GND")
	)
	(via
		(at 97.653094 -262.058658)
		(size 0.4572)
		(drill 0.2032)
		(layers "F.Cu" "B.Cu")
		(net "GND")
	)
	(via
		(at 379.895862 -277.522432)
		(size 0.4572)
		(drill 0.2032)
		(layers "F.Cu" "B.Cu")
		(net "GND")
	)
	(via
		(at 167.164766 -404.51786)
		(size 0.4572)
		(drill 0.254)
		(layers "F.Cu" "B.Cu")
		(net "GND")
	)
	(via
		(at 370.858034 -219.506038)
		(size 0.4572)
		(drill 0.2032)
		(layers "F.Cu" "B.Cu")
		(net "GND")
	)
	(via
		(at 369.088416 -279.964134)
		(size 0.4572)
		(drill 0.2032)
		(layers "F.Cu" "B.Cu")
		(net "GND")
	)
	(via
		(at 31.876746 -276.366732)
		(size 0.4572)
		(drill 0.2032)
		(layers "F.Cu" "B.Cu")
		(net "GND")
	)
	(via
		(at 13.800582 -407.507186)
		(size 0.508)
		(drill 0.254)
		(layers "F.Cu" "B.Cu")
		(net "GND")
	)
	(via
		(at 371.437662 -272.639282)
		(size 0.4572)
		(drill 0.2032)
		(layers "F.Cu" "B.Cu")
		(net "GND")
	)
	(via
		(at 27.823668 -4.328668)
		(size 0.508)
		(drill 0.254)
		(layers "F.Cu" "B.Cu")
		(net "GND")
	)
	(via
		(at 28.433014 -202.416664)
		(size 0.4572)
		(drill 0.2032)
		(layers "F.Cu" "B.Cu")
		(net "GND")
	)
	(via
		(at 430.489614 -227.066602)
		(size 0.4572)
		(drill 0.2032)
		(layers "F.Cu" "B.Cu")
		(net "GND")
	)
	(via
		(at 131.015994 -262.872474)
		(size 0.4572)
		(drill 0.2032)
		(layers "F.Cu" "B.Cu")
		(net "GND")
	)
	(via
		(at 450.911214 -279.766776)
		(size 0.4572)
		(drill 0.2032)
		(layers "F.Cu" "B.Cu")
		(net "GND")
	)
	(via
		(at 405.64689 -10.16508)
		(size 0.508)
		(drill 0.254)
		(layers "F.Cu" "B.Cu")
		(net "GND")
	)
	(via
		(at 93.730826 -401.492212)
		(size 0.4572)
		(drill 0.254)
		(layers "F.Cu" "B.Cu")
		(net "GND")
	)
	(via
		(at 101.617018 -331.043026)
		(size 0.508)
		(drill 0.254)
		(layers "F.Cu" "B.Cu")
		(net "GND")
	)
	(via
		(at 427.045882 -312.91657)
		(size 0.4572)
		(drill 0.2032)
		(layers "F.Cu" "B.Cu")
		(net "GND")
	)
	(via
		(at 433.50688 -178.755548)
		(size 0.508)
		(drill 0.254)
		(layers "F.Cu" "B.Cu")
		(net "GND")
	)
	(via
		(at 399.349976 -436.347362)
		(size 0.4572)
		(drill 0.2032)
		(layers "F.Cu" "B.Cu")
		(net "GND")
	)
	(via
		(at 18.679414 -244.066568)
		(size 0.4572)
		(drill 0.2032)
		(layers "F.Cu" "B.Cu")
		(net "GND")
	)
	(via
		(at 104.591866 -220.319854)
		(size 0.4572)
		(drill 0.2032)
		(layers "F.Cu" "B.Cu")
		(net "GND")
	)
	(via
		(at 307.813964 -441.225432)
		(size 0.508)
		(drill 0.254)
		(layers "F.Cu" "B.Cu")
		(net "GND")
	)
	(via
		(at 27.77109 -16.978376)
		(size 0.508)
		(drill 0.254)
		(layers "F.Cu" "B.Cu")
		(net "GND")
	)
	(via
		(at 354.377498 -235.27131)
		(size 0.4572)
		(drill 0.2032)
		(layers "F.Cu" "B.Cu")
		(net "GND")
	)
	(via
		(at 168.066974 -12.495022)
		(size 0.508)
		(drill 0.254)
		(layers "F.Cu" "B.Cu")
		(net "GND")
	)
	(via
		(at 455.011282 -316.316614)
		(size 0.4572)
		(drill 0.2032)
		(layers "F.Cu" "B.Cu")
		(net "GND")
	)
	(via
		(at 331.069188 -53.149246)
		(size 0.4572)
		(drill 0.2032)
		(layers "F.Cu" "B.Cu")
		(net "GND")
	)
	(via
		(at 37.210746 -300.166786)
		(size 0.4572)
		(drill 0.2032)
		(layers "F.Cu" "B.Cu")
		(net "GND")
	)
	(via
		(at 299.004482 -222.816674)
		(size 0.4572)
		(drill 0.2032)
		(layers "F.Cu" "B.Cu")
		(net "GND")
	)
	(via
		(at 259.075682 -286.56661)
		(size 0.4572)
		(drill 0.2032)
		(layers "F.Cu" "B.Cu")
		(net "GND")
	)
	(via
		(at 276.373082 -210.066636)
		(size 0.4572)
		(drill 0.2032)
		(layers "F.Cu" "B.Cu")
		(net "GND")
	)
	(via
		(at 319.098676 -403.249892)
		(size 0.4572)
		(drill 0.254)
		(layers "F.Cu" "B.Cu")
		(net "GND")
	)
	(via
		(at 171.562014 -250.866656)
		(size 0.4572)
		(drill 0.2032)
		(layers "F.Cu" "B.Cu")
		(net "GND")
	)
	(via
		(at 405.64689 -9.424924)
		(size 0.508)
		(drill 0.254)
		(layers "F.Cu" "B.Cu")
		(net "GND")
	)
	(via
		(at 46.964346 -273.816572)
		(size 0.4572)
		(drill 0.2032)
		(layers "F.Cu" "B.Cu")
		(net "GND")
	)
	(via
		(at 53.682392 -174.774098)
		(size 0.508)
		(drill 0.254)
		(layers "F.Cu" "B.Cu")
		(net "GND")
	)
	(via
		(at 138.239754 -407.00452)
		(size 0.4064)
		(drill 0.2032)
		(layers "F.Cu" "B.Cu")
		(net "GND")
	)
	(via
		(at 457.221082 -282.316682)
		(size 0.4572)
		(drill 0.2032)
		(layers "F.Cu" "B.Cu")
		(net "GND")
	)
	(via
		(at 310.207914 -217.716608)
		(size 0.4572)
		(drill 0.2032)
		(layers "F.Cu" "B.Cu")
		(net "GND")
	)
	(via
		(at 371.437662 -257.98907)
		(size 0.4572)
		(drill 0.2032)
		(layers "F.Cu" "B.Cu")
		(net "GND")
	)
	(via
		(at 346.893134 -226.831144)
		(size 0.4572)
		(drill 0.2032)
		(layers "F.Cu" "B.Cu")
		(net "GND")
	)
	(via
		(at 281.707082 -299.316648)
		(size 0.4572)
		(drill 0.2032)
		(layers "F.Cu" "B.Cu")
		(net "GND")
	)
	(via
		(at 186.649614 -235.566712)
		(size 0.4572)
		(drill 0.2032)
		(layers "F.Cu" "B.Cu")
		(net "GND")
	)
	(via
		(at 374.893586 -351.796858)
		(size 0.508)
		(drill 0.254)
		(layers "F.Cu" "B.Cu")
		(net "GND")
	)
	(via
		(at 44.754546 -204.96657)
		(size 0.4572)
		(drill 0.2032)
		(layers "F.Cu" "B.Cu")
		(net "GND")
	)
	(via
		(at 335.725262 -259.616956)
		(size 0.4572)
		(drill 0.2032)
		(layers "F.Cu" "B.Cu")
		(net "GND")
	)
	(via
		(at 257.185414 -199.01662)
		(size 0.4572)
		(drill 0.2032)
		(layers "F.Cu" "B.Cu")
		(net "GND")
	)
	(via
		(at 417.292282 -289.966654)
		(size 0.4572)
		(drill 0.2032)
		(layers "F.Cu" "B.Cu")
		(net "GND")
	)
	(via
		(at 332.326234 -247.178322)
		(size 0.4572)
		(drill 0.2032)
		(layers "F.Cu" "B.Cu")
		(net "GND")
	)
	(via
		(at 325.250048 -439.651394)
		(size 0.4572)
		(drill 0.2032)
		(layers "F.Cu" "B.Cu")
		(net "GND")
	)
	(via
		(at 347.002862 -284.033722)
		(size 0.4572)
		(drill 0.2032)
		(layers "F.Cu" "B.Cu")
		(net "GND")
	)
	(via
		(at 380.256034 -248.806208)
		(size 0.4572)
		(drill 0.2032)
		(layers "F.Cu" "B.Cu")
		(net "GND")
	)
	(via
		(at 125.847348 -281.59202)
		(size 0.4572)
		(drill 0.2032)
		(layers "F.Cu" "B.Cu")
		(net "GND")
	)
	(via
		(at 250.360688 -109.972094)
		(size 0.508)
		(drill 0.254)
		(layers "F.Cu" "B.Cu")
		(net "GND")
	)
	(via
		(at 365.044228 -330.604114)
		(size 0.508)
		(drill 0.254)
		(layers "F.Cu" "B.Cu")
		(net "GND")
	)
	(via
		(at 435.823614 -227.066602)
		(size 0.4572)
		(drill 0.2032)
		(layers "F.Cu" "B.Cu")
		(net "GND")
	)
	(via
		(at 97.653348 -258.80314)
		(size 0.4572)
		(drill 0.2032)
		(layers "F.Cu" "B.Cu")
		(net "GND")
	)
	(via
		(at 257.185414 -311.216802)
		(size 0.4572)
		(drill 0.2032)
		(layers "F.Cu" "B.Cu")
		(net "GND")
	)
	(via
		(at 317.29426 -400.224244)
		(size 0.4572)
		(drill 0.254)
		(layers "F.Cu" "B.Cu")
		(net "GND")
	)
	(via
		(at 182.549546 -221.96679)
		(size 0.4572)
		(drill 0.2032)
		(layers "F.Cu" "B.Cu")
		(net "GND")
	)
	(via
		(at 110.340394 -284.033722)
		(size 0.4572)
		(drill 0.2032)
		(layers "F.Cu" "B.Cu")
		(net "GND")
	)
	(via
		(at 377.668536 -95.081852)
		(size 0.508)
		(drill 0.254)
		(layers "F.Cu" "B.Cu")
		(net "GND")
	)
	(via
		(at 82.250026 -428.851314)
		(size 0.4572)
		(drill 0.2032)
		(layers "F.Cu" "B.Cu")
		(net "GND")
	)
	(via
		(at 108.820966 -232.528364)
		(size 0.4572)
		(drill 0.2032)
		(layers "F.Cu" "B.Cu")
		(net "GND")
	)
	(via
		(at 291.460682 -266.1666)
		(size 0.4572)
		(drill 0.2032)
		(layers "F.Cu" "B.Cu")
		(net "GND")
	)
	(via
		(at 119.628666 -217.064336)
		(size 0.4572)
		(drill 0.2032)
		(layers "F.Cu" "B.Cu")
		(net "GND")
	)
	(via
		(at 295.092374 -322.499736)
		(size 0.4572)
		(drill 0.2032)
		(layers "F.Cu" "B.Cu")
		(net "GND")
	)
	(via
		(at 191.816482 -434.3019)
		(size 0.508)
		(drill 0.254)
		(layers "F.Cu" "B.Cu")
		(net "GND")
	)
	(via
		(at 58.608214 -228.766624)
		(size 0.4572)
		(drill 0.2032)
		(layers "F.Cu" "B.Cu")
		(net "GND")
	)
	(via
		(at 460.664814 -233.016806)
		(size 0.4572)
		(drill 0.2032)
		(layers "F.Cu" "B.Cu")
		(net "GND")
	)
	(via
		(at 256.70002 -190.180214)
		(size 0.508)
		(drill 0.254)
		(layers "F.Cu" "B.Cu")
		(net "GND")
	)
	(via
		(at 40.413178 -399.126456)
		(size 0.508)
		(drill 0.254)
		(layers "F.Cu" "B.Cu")
		(net "GND")
	)
	(via
		(at 304.338482 -280.61666)
		(size 0.4572)
		(drill 0.2032)
		(layers "F.Cu" "B.Cu")
		(net "GND")
	)
	(via
		(at 420.736014 -261.916672)
		(size 0.4572)
		(drill 0.2032)
		(layers "F.Cu" "B.Cu")
		(net "GND")
	)
	(via
		(at 340.08314 -407.638504)
		(size 0.4572)
		(drill 0.254)
		(layers "F.Cu" "B.Cu")
		(net "GND")
	)
	(via
		(at 25.746964 -9.424924)
		(size 0.508)
		(drill 0.254)
		(layers "F.Cu" "B.Cu")
		(net "GND")
	)
	(via
		(at 231.57688 -129.962148)
		(size 0.508)
		(drill 0.254)
		(layers "F.Cu" "B.Cu")
		(net "GND")
	)
	(via
		(at 92.013786 -409.396184)
		(size 0.4572)
		(drill 0.254)
		(layers "F.Cu" "B.Cu")
		(net "GND")
	)
	(via
		(at 126.677166 -226.017328)
		(size 0.4572)
		(drill 0.2032)
		(layers "F.Cu" "B.Cu")
		(net "GND")
	)
	(via
		(at 364.82782 -386.372608)
		(size 0.508)
		(drill 0.254)
		(layers "F.Cu" "B.Cu")
		(net "GND")
	)
	(via
		(at 89.085166 -247.178322)
		(size 0.4572)
		(drill 0.2032)
		(layers "F.Cu" "B.Cu")
		(net "GND")
	)
	(via
		(at 261.285482 -264.466578)
		(size 0.4572)
		(drill 0.2032)
		(layers "F.Cu" "B.Cu")
		(net "GND")
	)
	(via
		(at 445.577214 -285.716726)
		(size 0.4572)
		(drill 0.2032)
		(layers "F.Cu" "B.Cu")
		(net "GND")
	)
	(via
		(at 464.764882 -271.266666)
		(size 0.4572)
		(drill 0.2032)
		(layers "F.Cu" "B.Cu")
		(net "GND")
	)
	(via
		(at 419.502082 -241.516662)
		(size 0.4572)
		(drill 0.2032)
		(layers "F.Cu" "B.Cu")
		(net "GND")
	)
	(via
		(at 161.808414 -204.116686)
		(size 0.4572)
		(drill 0.2032)
		(layers "F.Cu" "B.Cu")
		(net "GND")
	)
	(via
		(at 66.152014 -286.56661)
		(size 0.4572)
		(drill 0.2032)
		(layers "F.Cu" "B.Cu")
		(net "GND")
	)
	(via
		(at 80.25003 -435.0512)
		(size 0.4572)
		(drill 0.2032)
		(layers "F.Cu" "B.Cu")
		(net "GND")
	)
	(via
		(at 432.379882 -282.316682)
		(size 0.4572)
		(drill 0.2032)
		(layers "F.Cu" "B.Cu")
		(net "GND")
	)
	(via
		(at 268.829282 -306.96662)
		(size 0.4572)
		(drill 0.2032)
		(layers "F.Cu" "B.Cu")
		(net "GND")
	)
	(via
		(at 205.180946 -270.416782)
		(size 0.4572)
		(drill 0.2032)
		(layers "F.Cu" "B.Cu")
		(net "GND")
	)
	(via
		(at 370.967762 -273.453098)
		(size 0.4572)
		(drill 0.2032)
		(layers "F.Cu" "B.Cu")
		(net "GND")
	)
	(via
		(at 391.22477 -403.883876)
		(size 0.4064)
		(drill 0.2032)
		(layers "F.Cu" "B.Cu")
		(net "GND")
	)
	(via
		(at 29.666946 -203.266802)
		(size 0.4572)
		(drill 0.2032)
		(layers "F.Cu" "B.Cu")
		(net "GND")
	)
	(via
		(at 421.15359 -171.071794)
		(size 0.508)
		(drill 0.254)
		(layers "F.Cu" "B.Cu")
		(net "GND")
	)
	(via
		(at 261.285482 -301.01667)
		(size 0.4572)
		(drill 0.2032)
		(layers "F.Cu" "B.Cu")
		(net "GND")
	)
	(via
		(at 57.146698 -323.47789)
		(size 0.4572)
		(drill 0.2032)
		(layers "F.Cu" "B.Cu")
		(net "GND")
	)
	(via
		(at 207.071214 -314.616592)
		(size 0.4572)
		(drill 0.2032)
		(layers "F.Cu" "B.Cu")
		(net "GND")
	)
	(via
		(at 252.122432 -109.972094)
		(size 0.508)
		(drill 0.254)
		(layers "F.Cu" "B.Cu")
		(net "GND")
	)
	(via
		(at 449.677282 -233.86669)
		(size 0.4572)
		(drill 0.2032)
		(layers "F.Cu" "B.Cu")
		(net "GND")
	)
	(via
		(at 38.897052 -393.454128)
		(size 0.508)
		(drill 0.254)
		(layers "F.Cu" "B.Cu")
		(net "GND")
	)
	(via
		(at 251.90958 -106.38409)
		(size 0.508)
		(drill 0.254)
		(layers "F.Cu" "B.Cu")
		(net "GND")
	)
	(via
		(at 417.997894 -180.964078)
		(size 0.49022)
		(drill 0.254)
		(layers "F.Cu" "B.Cu")
		(net "GND")
	)
	(via
		(at 37.210746 -267.016738)
		(size 0.4572)
		(drill 0.2032)
		(layers "F.Cu" "B.Cu")
		(net "GND")
	)
	(via
		(at 91.544394 -261.244842)
		(size 0.4572)
		(drill 0.2032)
		(layers "F.Cu" "B.Cu")
		(net "GND")
	)
	(via
		(at 144.188942 -33.157668)
		(size 0.508)
		(drill 0.254)
		(layers "F.Cu" "B.Cu")
		(net "GND")
	)
	(via
		(at 287.360614 -212.616796)
		(size 0.4572)
		(drill 0.2032)
		(layers "F.Cu" "B.Cu")
		(net "GND")
	)
	(via
		(at 88.145366 -230.900478)
		(size 0.4572)
		(drill 0.2032)
		(layers "F.Cu" "B.Cu")
		(net "GND")
	)
	(via
		(at 357.717344 -332.363826)
		(size 0.508)
		(drill 0.254)
		(layers "F.Cu" "B.Cu")
		(net "GND")
	)
	(via
		(at 22.123146 -298.466764)
		(size 0.4572)
		(drill 0.2032)
		(layers "F.Cu" "B.Cu")
		(net "GND")
	)
	(via
		(at 164.018214 -297.616626)
		(size 0.4572)
		(drill 0.2032)
		(layers "F.Cu" "B.Cu")
		(net "GND")
	)
	(via
		(at 6.287516 -55.93588)
		(size 0.508)
		(drill 0.254)
		(layers "F.Cu" "B.Cu")
		(net "GND")
	)
	(via
		(at 31.876746 -206.666592)
		(size 0.4572)
		(drill 0.2032)
		(layers "F.Cu" "B.Cu")
		(net "GND")
	)
	(via
		(at 184.439814 -262.76681)
		(size 0.4572)
		(drill 0.2032)
		(layers "F.Cu" "B.Cu")
		(net "GND")
	)
	(via
		(at 418.089588 -18.235422)
		(size 0.508)
		(drill 0.254)
		(layers "F.Cu" "B.Cu")
		(net "GND")
	)
	(via
		(at 94.723712 -229.272846)
		(size 0.4572)
		(drill 0.2032)
		(layers "F.Cu" "B.Cu")
		(net "GND")
	)
	(via
		(at 381.775462 -287.28924)
		(size 0.4572)
		(drill 0.2032)
		(layers "F.Cu" "B.Cu")
		(net "GND")
	)
	(via
		(at 137.594594 -287.28924)
		(size 0.4572)
		(drill 0.2032)
		(layers "F.Cu" "B.Cu")
		(net "GND")
	)
	(via
		(at 151.349964 -426.69968)
		(size 0.4572)
		(drill 0.2032)
		(layers "F.Cu" "B.Cu")
		(net "GND")
	)
	(via
		(at 207.071214 -303.566576)
		(size 0.4572)
		(drill 0.2032)
		(layers "F.Cu" "B.Cu")
		(net "GND")
	)
	(via
		(at 394.776706 -35.118802)
		(size 0.508)
		(drill 0.254)
		(layers "F.Cu" "B.Cu")
		(net "GND")
	)
	(via
		(at 62.051946 -304.416714)
		(size 0.4572)
		(drill 0.2032)
		(layers "F.Cu" "B.Cu")
		(net "GND")
	)
	(via
		(at 372.7577 -365.669068)
		(size 0.508)
		(drill 0.254)
		(layers "F.Cu" "B.Cu")
		(net "GND")
	)
	(via
		(at 24.332946 -285.716726)
		(size 0.4572)
		(drill 0.2032)
		(layers "F.Cu" "B.Cu")
		(net "GND")
	)
	(via
		(at 58.065162 -150.93188)
		(size 0.508)
		(drill 0.254)
		(layers "F.Cu" "B.Cu")
		(net "GND")
	)
	(via
		(at 108.025946 -329.76312)
		(size 0.508)
		(drill 0.254)
		(layers "F.Cu" "B.Cu")
		(net "GND")
	)
	(via
		(at 352.641662 -285.661354)
		(size 0.4572)
		(drill 0.2032)
		(layers "F.Cu" "B.Cu")
		(net "GND")
	)
	(via
		(at 176.896014 -245.76659)
		(size 0.4572)
		(drill 0.2032)
		(layers "F.Cu" "B.Cu")
		(net "GND")
	)
	(via
		(at 38.651434 -124.61621)
		(size 0.508)
		(drill 0.254)
		(layers "F.Cu" "B.Cu")
		(net "GND")
	)
	(via
		(at 356.718108 -35.240468)
		(size 0.508)
		(drill 0.254)
		(layers "F.Cu" "B.Cu")
		(net "GND")
	)
	(via
		(at 432.379882 -316.316614)
		(size 0.4572)
		(drill 0.2032)
		(layers "F.Cu" "B.Cu")
		(net "GND")
	)
	(via
		(at 327.741788 -75.452224)
		(size 0.508)
		(drill 0.254)
		(layers "F.Cu" "B.Cu")
		(net "GND")
	)
	(via
		(at 309.811928 -407.00452)
		(size 0.4064)
		(drill 0.2032)
		(layers "F.Cu" "B.Cu")
		(net "GND")
	)
	(via
		(at 382.605534 -218.692222)
		(size 0.4572)
		(drill 0.2032)
		(layers "F.Cu" "B.Cu")
		(net "GND")
	)
	(via
		(at 124.005594 -407.00452)
		(size 0.4064)
		(drill 0.2032)
		(layers "F.Cu" "B.Cu")
		(net "GND")
	)
	(via
		(at 275.373084 -17.043908)
		(size 0.508)
		(drill 0.254)
		(layers "F.Cu" "B.Cu")
		(net "GND")
	)
	(via
		(at 241.965988 -134.458456)
		(size 0.508)
		(drill 0.254)
		(layers "F.Cu" "B.Cu")
		(net "GND")
	)
	(via
		(at 165.252146 -268.71676)
		(size 0.4572)
		(drill 0.2032)
		(layers "F.Cu" "B.Cu")
		(net "GND")
	)
	(via
		(at 43.520614 -205.816708)
		(size 0.4572)
		(drill 0.2032)
		(layers "F.Cu" "B.Cu")
		(net "GND")
	)
	(via
		(at 399.349976 -433.899564)
		(size 0.4572)
		(drill 0.2032)
		(layers "F.Cu" "B.Cu")
		(net "GND")
	)
	(via
		(at 336.250026 -427.851316)
		(size 0.4572)
		(drill 0.2032)
		(layers "F.Cu" "B.Cu")
		(net "GND")
	)
	(via
		(at 368.038634 -226.017328)
		(size 0.4572)
		(drill 0.2032)
		(layers "F.Cu" "B.Cu")
		(net "GND")
	)
	(via
		(at 307.566314 -276.366732)
		(size 0.4572)
		(drill 0.2032)
		(layers "F.Cu" "B.Cu")
		(net "GND")
	)
	(via
		(at 67.42049 -400.200368)
		(size 0.4572)
		(drill 0.254)
		(layers "F.Cu" "B.Cu")
		(net "GND")
	)
	(via
		(at 375.197116 -257.98907)
		(size 0.4572)
		(drill 0.2032)
		(layers "F.Cu" "B.Cu")
		(net "GND")
	)
	(via
		(at 85.43798 -103.200708)
		(size 0.508)
		(drill 0.254)
		(layers "F.Cu" "B.Cu")
		(net "GND")
	)
	(via
		(at 93.314266 -223.575626)
		(size 0.4572)
		(drill 0.2032)
		(layers "F.Cu" "B.Cu")
		(net "GND")
	)
	(via
		(at 294.904414 -206.666592)
		(size 0.4572)
		(drill 0.2032)
		(layers "F.Cu" "B.Cu")
		(net "GND")
	)
	(via
		(at 25.99055 -4.962652)
		(size 0.508)
		(drill 0.254)
		(layers "F.Cu" "B.Cu")
		(net "GND")
	)
	(via
		(at 108.686346 -331.08392)
		(size 0.508)
		(drill 0.254)
		(layers "F.Cu" "B.Cu")
		(net "GND")
	)
	(via
		(at 384.124962 -283.219906)
		(size 0.4572)
		(drill 0.2032)
		(layers "F.Cu" "B.Cu")
		(net "GND")
	)
	(via
		(at 62.051946 -212.616796)
		(size 0.4572)
		(drill 0.2032)
		(layers "F.Cu" "B.Cu")
		(net "GND")
	)
	(via
		(at 458.455014 -231.316784)
		(size 0.4572)
		(drill 0.2032)
		(layers "F.Cu" "B.Cu")
		(net "GND")
	)
	(via
		(at 59.938158 -407.00452)
		(size 0.4064)
		(drill 0.2032)
		(layers "F.Cu" "B.Cu")
		(net "GND")
	)
	(via
		(at 129.966212 -230.086662)
		(size 0.4572)
		(drill 0.2032)
		(layers "F.Cu" "B.Cu")
		(net "GND")
	)
	(via
		(at 341.724234 -222.761556)
		(size 0.4572)
		(drill 0.2032)
		(layers "F.Cu" "B.Cu")
		(net "GND")
	)
	(via
		(at 47.360078 -99.840034)
		(size 0.508)
		(drill 0.254)
		(layers "F.Cu" "B.Cu")
		(net "GND")
	)
	(via
		(at 412.00324 -219.41663)
		(size 0.4572)
		(drill 0.2032)
		(layers "F.Cu" "B.Cu")
		(net "GND")
	)
	(via
		(at 352.172016 -279.964134)
		(size 0.4572)
		(drill 0.2032)
		(layers "F.Cu" "B.Cu")
		(net "GND")
	)
	(via
		(at 169.352214 -301.01667)
		(size 0.4572)
		(drill 0.2032)
		(layers "F.Cu" "B.Cu")
		(net "GND")
	)
	(via
		(at 336.085434 -229.272846)
		(size 0.4572)
		(drill 0.2032)
		(layers "F.Cu" "B.Cu")
		(net "GND")
	)
	(via
		(at 107.322366 -333.356458)
		(size 0.49022)
		(drill 0.254)
		(layers "F.Cu" "B.Cu")
		(net "GND")
	)
	(via
		(at 389.832596 -26.185622)
		(size 0.508)
		(drill 0.254)
		(layers "F.Cu" "B.Cu")
		(net "GND")
	)
	(via
		(at 405.648414 -289.11677)
		(size 0.4572)
		(drill 0.2032)
		(layers "F.Cu" "B.Cu")
		(net "GND")
	)
	(via
		(at 283.916882 -262.76681)
		(size 0.4572)
		(drill 0.2032)
		(layers "F.Cu" "B.Cu")
		(net "GND")
	)
	(via
		(at 215.57234 -128.432814)
		(size 0.508)
		(drill 0.254)
		(layers "F.Cu" "B.Cu")
		(net "GND")
	)
	(via
		(at 201.737214 -200.716642)
		(size 0.4572)
		(drill 0.2032)
		(layers "F.Cu" "B.Cu")
		(net "GND")
	)
	(via
		(at 348.882462 -259.616956)
		(size 0.4572)
		(drill 0.2032)
		(layers "F.Cu" "B.Cu")
		(net "GND")
	)
	(via
		(at 139.229084 -245.27256)
		(size 0.4572)
		(drill 0.2032)
		(layers "F.Cu" "B.Cu")
		(net "GND")
	)
	(via
		(at 194.193414 -294.216582)
		(size 0.4572)
		(drill 0.2032)
		(layers "F.Cu" "B.Cu")
		(net "GND")
	)
	(via
		(at 223.640142 -83.65998)
		(size 0.508)
		(drill 0.254)
		(layers "F.Cu" "B.Cu")
		(net "GND")
	)
	(via
		(at 18.679414 -297.616626)
		(size 0.4572)
		(drill 0.2032)
		(layers "F.Cu" "B.Cu")
		(net "GND")
	)
	(via
		(at 351.077276 -410.664152)
		(size 0.4572)
		(drill 0.254)
		(layers "F.Cu" "B.Cu")
		(net "GND")
	)
	(via
		(at 282.444952 -323.429376)
		(size 0.4572)
		(drill 0.2032)
		(layers "F.Cu" "B.Cu")
		(net "GND")
	)
	(via
		(at 14.579346 -307.816758)
		(size 0.4572)
		(drill 0.2032)
		(layers "F.Cu" "B.Cu")
		(net "GND")
	)
	(via
		(at 309.992014 -195.616576)
		(size 0.4572)
		(drill 0.2032)
		(layers "F.Cu" "B.Cu")
		(net "GND")
	)
	(via
		(at 309.992014 -306.116736)
		(size 0.4572)
		(drill 0.2032)
		(layers "F.Cu" "B.Cu")
		(net "GND")
	)
	(via
		(at 314.318396 -410.664152)
		(size 0.4572)
		(drill 0.254)
		(layers "F.Cu" "B.Cu")
		(net "GND")
	)
	(via
		(at 397.717772 -19.125438)
		(size 0.508)
		(drill 0.254)
		(layers "F.Cu" "B.Cu")
		(net "GND")
	)
	(via
		(at 416.554412 -19.759422)
		(size 0.508)
		(drill 0.254)
		(layers "F.Cu" "B.Cu")
		(net "GND")
	)
	(via
		(at 450.911214 -229.616762)
		(size 0.4572)
		(drill 0.2032)
		(layers "F.Cu" "B.Cu")
		(net "GND")
	)
	(via
		(at 439.923682 -213.46668)
		(size 0.4572)
		(drill 0.2032)
		(layers "F.Cu" "B.Cu")
		(net "GND")
	)
	(via
		(at 129.496566 -235.783882)
		(size 0.4572)
		(drill 0.2032)
		(layers "F.Cu" "B.Cu")
		(net "GND")
	)
	(via
		(at 171.562014 -230.466646)
		(size 0.4572)
		(drill 0.2032)
		(layers "F.Cu" "B.Cu")
		(net "GND")
	)
	(via
		(at 408.061414 -272.116804)
		(size 0.4572)
		(drill 0.2032)
		(layers "F.Cu" "B.Cu")
		(net "GND")
	)
	(via
		(at 277.607014 -278.066754)
		(size 0.4572)
		(drill 0.2032)
		(layers "F.Cu" "B.Cu")
		(net "GND")
	)
	(via
		(at 20.889214 -239.81664)
		(size 0.4572)
		(drill 0.2032)
		(layers "F.Cu" "B.Cu")
		(net "GND")
	)
	(via
		(at 357.700834 -222.761556)
		(size 0.4572)
		(drill 0.2032)
		(layers "F.Cu" "B.Cu")
		(net "GND")
	)
	(via
		(at 438.033414 -265.316716)
		(size 0.4572)
		(drill 0.2032)
		(layers "F.Cu" "B.Cu")
		(net "GND")
	)
	(via
		(at 160.170622 -206.666592)
		(size 0.4572)
		(drill 0.2032)
		(layers "F.Cu" "B.Cu")
		(net "GND")
	)
	(via
		(at 471.03538 -69.184266)
		(size 0.508)
		(drill 0.254)
		(layers "F.Cu" "B.Cu")
		(net "GND")
	)
	(via
		(at 96.603566 -216.25052)
		(size 0.4572)
		(drill 0.2032)
		(layers "F.Cu" "B.Cu")
		(net "GND")
	)
	(via
		(at 142.658846 -401.492212)
		(size 0.4572)
		(drill 0.254)
		(layers "F.Cu" "B.Cu")
		(net "GND")
	)
	(via
		(at 455.011282 -204.116686)
		(size 0.4572)
		(drill 0.2032)
		(layers "F.Cu" "B.Cu")
		(net "GND")
	)
	(via
		(at 342.774016 -257.175254)
		(size 0.4572)
		(drill 0.2032)
		(layers "F.Cu" "B.Cu")
		(net "GND")
	)
	(via
		(at 58.725562 -150.93188)
		(size 0.508)
		(drill 0.254)
		(layers "F.Cu" "B.Cu")
		(net "GND")
	)
	(via
		(at 417.173918 -403.249892)
		(size 0.4572)
		(drill 0.254)
		(layers "F.Cu" "B.Cu")
		(net "GND")
	)
	(via
		(at 117.279166 -216.25052)
		(size 0.4572)
		(drill 0.2032)
		(layers "F.Cu" "B.Cu")
		(net "GND")
	)
	(via
		(at 187.883546 -240.666778)
		(size 0.4572)
		(drill 0.2032)
		(layers "F.Cu" "B.Cu")
		(net "GND")
	)
	(via
		(at 58.608214 -305.266598)
		(size 0.4572)
		(drill 0.2032)
		(layers "F.Cu" "B.Cu")
		(net "GND")
	)
	(via
		(at 106.348022 -239.292892)
		(size 0.4572)
		(drill 0.2032)
		(layers "F.Cu" "B.Cu")
		(net "GND")
	)
	(via
		(at 268.829282 -303.566576)
		(size 0.4572)
		(drill 0.2032)
		(layers "F.Cu" "B.Cu")
		(net "GND")
	)
	(via
		(at 122.069098 -328.68489)
		(size 0.6604)
		(drill 0.3302)
		(layers "F.Cu" "B.Cu")
		(net "GND")
	)
	(via
		(at 354.051616 -265.314176)
		(size 0.4572)
		(drill 0.2032)
		(layers "F.Cu" "B.Cu")
		(net "GND")
	)
	(via
		(at 83.54441 -340.284816)
		(size 0.508)
		(drill 0.254)
		(layers "F.Cu" "B.Cu")
		(net "GND")
	)
	(via
		(at 372.286784 -330.42352)
		(size 0.508)
		(drill 0.254)
		(layers "F.Cu" "B.Cu")
		(net "GND")
	)
	(via
		(at 214.615014 -261.066788)
		(size 0.4572)
		(drill 0.2032)
		(layers "F.Cu" "B.Cu")
		(net "GND")
	)
	(via
		(at 56.398414 -277.216616)
		(size 0.4572)
		(drill 0.2032)
		(layers "F.Cu" "B.Cu")
		(net "GND")
	)
	(via
		(at 214.615014 -194.766692)
		(size 0.4572)
		(drill 0.2032)
		(layers "F.Cu" "B.Cu")
		(net "GND")
	)
	(via
		(at 420.156894 -12.37488)
		(size 0.508)
		(drill 0.254)
		(layers "F.Cu" "B.Cu")
		(net "GND")
	)
	(via
		(at 261.285482 -196.466714)
		(size 0.4572)
		(drill 0.2032)
		(layers "F.Cu" "B.Cu")
		(net "GND")
	)
	(via
		(at 41.310814 -224.516696)
		(size 0.4572)
		(drill 0.2032)
		(layers "F.Cu" "B.Cu")
		(net "GND")
	)
	(via
		(at 187.356242 -25.109932)
		(size 0.508)
		(drill 0.254)
		(layers "F.Cu" "B.Cu")
		(net "GND")
	)
	(via
		(at 186.649614 -289.966654)
		(size 0.4572)
		(drill 0.2032)
		(layers "F.Cu" "B.Cu")
		(net "GND")
	)
	(via
		(at 283.916882 -238.116618)
		(size 0.4572)
		(drill 0.2032)
		(layers "F.Cu" "B.Cu")
		(net "GND")
	)
	(via
		(at 49.755552 -164.864034)
		(size 0.508)
		(drill 0.254)
		(layers "F.Cu" "B.Cu")
		(net "GND")
	)
	(via
		(at 460.664814 -221.96679)
		(size 0.4572)
		(drill 0.2032)
		(layers "F.Cu" "B.Cu")
		(net "GND")
	)
	(via
		(at 90.604848 -272.639282)
		(size 0.4572)
		(drill 0.2032)
		(layers "F.Cu" "B.Cu")
		(net "GND")
	)
	(via
		(at 144.005046 -410.664152)
		(size 0.4572)
		(drill 0.254)
		(layers "F.Cu" "B.Cu")
		(net "GND")
	)
	(via
		(at 257.185414 -201.56678)
		(size 0.4572)
		(drill 0.2032)
		(layers "F.Cu" "B.Cu")
		(net "GND")
	)
	(via
		(at 134.305294 -288.103056)
		(size 0.4572)
		(drill 0.2032)
		(layers "F.Cu" "B.Cu")
		(net "GND")
	)
	(via
		(at 257.185414 -225.36658)
		(size 0.4572)
		(drill 0.2032)
		(layers "F.Cu" "B.Cu")
		(net "GND")
	)
	(via
		(at 414.074356 -168.632378)
		(size 0.49022)
		(drill 0.254)
		(layers "F.Cu" "B.Cu")
		(net "GND")
	)
	(via
		(at 124.327412 -228.45903)
		(size 0.4572)
		(drill 0.2032)
		(layers "F.Cu" "B.Cu")
		(net "GND")
	)
	(via
		(at 99.532694 -257.175254)
		(size 0.4572)
		(drill 0.2032)
		(layers "F.Cu" "B.Cu")
		(net "GND")
	)
	(via
		(at 39.420546 -251.716794)
		(size 0.4572)
		(drill 0.2032)
		(layers "F.Cu" "B.Cu")
		(net "GND")
	)
	(via
		(at 256.049018 -49.366424)
		(size 0.508)
		(drill 0.254)
		(layers "F.Cu" "B.Cu")
		(net "GND")
	)
	(via
		(at 86.265766 -242.294918)
		(size 0.4572)
		(drill 0.2032)
		(layers "F.Cu" "B.Cu")
		(net "GND")
	)
	(via
		(at 161.757614 -271.266666)
		(size 0.4572)
		(drill 0.2032)
		(layers "F.Cu" "B.Cu")
		(net "GND")
	)
	(via
		(at 376.496834 -222.761556)
		(size 0.4572)
		(drill 0.2032)
		(layers "F.Cu" "B.Cu")
		(net "GND")
	)
	(via
		(at 445.577214 -317.166752)
		(size 0.4572)
		(drill 0.2032)
		(layers "F.Cu" "B.Cu")
		(net "GND")
	)
	(via
		(at 126.098554 -334.45323)
		(size 0.508)
		(drill 0.254)
		(layers "F.Cu" "B.Cu")
		(net "GND")
	)
	(via
		(at 97.543366 -243.922804)
		(size 0.4572)
		(drill 0.2032)
		(layers "F.Cu" "B.Cu")
		(net "GND")
	)
	(via
		(at 37.210746 -258.516628)
		(size 0.4572)
		(drill 0.2032)
		(layers "F.Cu" "B.Cu")
		(net "GND")
	)
	(via
		(at 381.8763 -97.204022)
		(size 0.508)
		(drill 0.254)
		(layers "F.Cu" "B.Cu")
		(net "GND")
	)
	(via
		(at 37.210746 -301.866808)
		(size 0.4572)
		(drill 0.2032)
		(layers "F.Cu" "B.Cu")
		(net "GND")
	)
	(via
		(at 100.472494 -283.219906)
		(size 0.4572)
		(drill 0.2032)
		(layers "F.Cu" "B.Cu")
		(net "GND")
	)
	(via
		(at 48.854614 -204.116686)
		(size 0.4572)
		(drill 0.2032)
		(layers "F.Cu" "B.Cu")
		(net "GND")
	)
	(via
		(at 281.715972 -387.615684)
		(size 0.508)
		(drill 0.254)
		(layers "F.Cu" "B.Cu")
		(net "GND")
	)
	(via
		(at 304.338482 -277.216616)
		(size 0.4572)
		(drill 0.2032)
		(layers "F.Cu" "B.Cu")
		(net "GND")
	)
	(via
		(at 145.722086 -401.492212)
		(size 0.4572)
		(drill 0.254)
		(layers "F.Cu" "B.Cu")
		(net "GND")
	)
	(via
		(at 444.74638 -369.867688)
		(size 0.49022)
		(drill 0.254)
		(layers "F.Cu" "B.Cu")
		(net "GND")
	)
	(via
		(at 182.549546 -306.116736)
		(size 0.4572)
		(drill 0.2032)
		(layers "F.Cu" "B.Cu")
		(net "GND")
	)
	(via
		(at 344.183462 -274.266914)
		(size 0.4572)
		(drill 0.2032)
		(layers "F.Cu" "B.Cu")
		(net "GND")
	)
	(via
		(at 106.941366 -216.25052)
		(size 0.4572)
		(drill 0.2032)
		(layers "F.Cu" "B.Cu")
		(net "GND")
	)
	(via
		(at 306.548282 -204.116686)
		(size 0.4572)
		(drill 0.2032)
		(layers "F.Cu" "B.Cu")
		(net "GND")
	)
	(via
		(at 424.166792 -7.215124)
		(size 0.508)
		(drill 0.254)
		(layers "F.Cu" "B.Cu")
		(net "GND")
	)
	(via
		(at 420.736014 -204.96657)
		(size 0.4572)
		(drill 0.2032)
		(layers "F.Cu" "B.Cu")
		(net "GND")
	)
	(via
		(at 428.279814 -306.116736)
		(size 0.4572)
		(drill 0.2032)
		(layers "F.Cu" "B.Cu")
		(net "GND")
	)
	(via
		(at 133.556502 -410.664152)
		(size 0.4572)
		(drill 0.254)
		(layers "F.Cu" "B.Cu")
		(net "GND")
	)
	(via
		(at 409.748482 -224.516696)
		(size 0.4572)
		(drill 0.2032)
		(layers "F.Cu" "B.Cu")
		(net "GND")
	)
	(via
		(at 335.145634 -245.55069)
		(size 0.4318)
		(drill 0.2032)
		(layers "F.Cu" "B.Cu")
		(net "GND")
	)
	(via
		(at 178.289204 -51.299872)
		(size 0.508)
		(drill 0.254)
		(layers "F.Cu" "B.Cu")
		(net "GND")
	)
	(via
		(at 36.66109 -19.13636)
		(size 0.508)
		(drill 0.254)
		(layers "F.Cu" "B.Cu")
		(net "GND")
	)
	(via
		(at 380.25578 -240.667286)
		(size 0.4572)
		(drill 0.2032)
		(layers "F.Cu" "B.Cu")
		(net "GND")
	)
	(via
		(at 169.352214 -239.81664)
		(size 0.4572)
		(drill 0.2032)
		(layers "F.Cu" "B.Cu")
		(net "GND")
	)
	(via
		(at 116.339366 -226.017328)
		(size 0.4572)
		(drill 0.2032)
		(layers "F.Cu" "B.Cu")
		(net "GND")
	)
	(via
		(at 409.748482 -308.666642)
		(size 0.4572)
		(drill 0.2032)
		(layers "F.Cu" "B.Cu")
		(net "GND")
	)
	(via
		(at 314.307982 -310.366664)
		(size 0.4572)
		(drill 0.2032)
		(layers "F.Cu" "B.Cu")
		(net "GND")
	)
	(via
		(at 20.889214 -305.266598)
		(size 0.4572)
		(drill 0.2032)
		(layers "F.Cu" "B.Cu")
		(net "GND")
	)
	(via
		(at 99.27082 -39.581582)
		(size 0.508)
		(drill 0.254)
		(layers "F.Cu" "B.Cu")
		(net "GND")
	)
	(via
		(at 177.988214 -21.0947)
		(size 0.508)
		(drill 0.254)
		(layers "F.Cu" "B.Cu")
		(net "GND")
	)
	(via
		(at 123.387612 -249.620024)
		(size 0.4572)
		(drill 0.2032)
		(layers "F.Cu" "B.Cu")
		(net "GND")
	)
	(via
		(at 125.264926 -123.112784)
		(size 0.508)
		(drill 0.254)
		(layers "F.Cu" "B.Cu")
		(net "GND")
	)
	(via
		(at 450.911214 -289.11677)
		(size 0.4572)
		(drill 0.2032)
		(layers "F.Cu" "B.Cu")
		(net "GND")
	)
	(via
		(at 47.150782 -351.644458)
		(size 0.508)
		(drill 0.254)
		(layers "F.Cu" "B.Cu")
		(net "GND")
	)
	(via
		(at 431.585624 -19.125438)
		(size 0.508)
		(drill 0.254)
		(layers "F.Cu" "B.Cu")
		(net "GND")
	)
	(via
		(at 135.245094 -281.59202)
		(size 0.4572)
		(drill 0.2032)
		(layers "F.Cu" "B.Cu")
		(net "GND")
	)
	(via
		(at 128.556766 -216.25052)
		(size 0.4572)
		(drill 0.2032)
		(layers "F.Cu" "B.Cu")
		(net "GND")
	)
	(via
		(at 181.66588 -102.707948)
		(size 0.508)
		(drill 0.254)
		(layers "F.Cu" "B.Cu")
		(net "GND")
	)
	(via
		(at 110.340394 -280.778204)
		(size 0.4572)
		(drill 0.2032)
		(layers "F.Cu" "B.Cu")
		(net "GND")
	)
	(via
		(at 349.242634 -240.667286)
		(size 0.4572)
		(drill 0.2032)
		(layers "F.Cu" "B.Cu")
		(net "GND")
	)
	(via
		(at 117.749066 -217.064336)
		(size 0.4572)
		(drill 0.2032)
		(layers "F.Cu" "B.Cu")
		(net "GND")
	)
	(via
		(at 380.835662 -271.011396)
		(size 0.4572)
		(drill 0.2032)
		(layers "F.Cu" "B.Cu")
		(net "GND")
	)
	(via
		(at 13.345414 -299.316648)
		(size 0.4572)
		(drill 0.2032)
		(layers "F.Cu" "B.Cu")
		(net "GND")
	)
	(via
		(at 458.455014 -307.816758)
		(size 0.4572)
		(drill 0.2032)
		(layers "F.Cu" "B.Cu")
		(net "GND")
	)
	(via
		(at 442.133482 -312.91657)
		(size 0.4572)
		(drill 0.2032)
		(layers "F.Cu" "B.Cu")
		(net "GND")
	)
	(via
		(at 309.992014 -279.766776)
		(size 0.4572)
		(drill 0.2032)
		(layers "F.Cu" "B.Cu")
		(net "GND")
	)
	(via
		(at 41.310814 -198.166736)
		(size 0.4572)
		(drill 0.2032)
		(layers "F.Cu" "B.Cu")
		(net "GND")
	)
	(via
		(at 90.278966 -335.187036)
		(size 0.49022)
		(drill 0.254)
		(layers "F.Cu" "B.Cu")
		(net "GND")
	)
	(via
		(at 185.988452 -352.639122)
		(size 0.508)
		(drill 0.254)
		(layers "F.Cu" "B.Cu")
		(net "GND")
	)
	(via
		(at 102.834694 -251.135134)
		(size 0.4572)
		(drill 0.2032)
		(layers "F.Cu" "B.Cu")
		(net "GND")
	)
	(via
		(at 100.832412 -233.34218)
		(size 0.4572)
		(drill 0.2032)
		(layers "F.Cu" "B.Cu")
		(net "GND")
	)
	(via
		(at 87.315294 -268.569694)
		(size 0.4318)
		(drill 0.2032)
		(layers "F.Cu" "B.Cu")
		(net "GND")
	)
	(via
		(at 386.834634 -224.389442)
		(size 0.4572)
		(drill 0.2032)
		(layers "F.Cu" "B.Cu")
		(net "GND")
	)
	(via
		(at 207.071214 -277.216616)
		(size 0.4572)
		(drill 0.2032)
		(layers "F.Cu" "B.Cu")
		(net "GND")
	)
	(via
		(at 430.489614 -300.166786)
		(size 0.4572)
		(drill 0.2032)
		(layers "F.Cu" "B.Cu")
		(net "GND")
	)
	(via
		(at 212.724746 -267.016738)
		(size 0.4572)
		(drill 0.2032)
		(layers "F.Cu" "B.Cu")
		(net "GND")
	)
	(via
		(at 385.534662 -262.872474)
		(size 0.4572)
		(drill 0.2032)
		(layers "F.Cu" "B.Cu")
		(net "GND")
	)
	(via
		(at 151.935942 -409.396184)
		(size 0.4572)
		(drill 0.254)
		(layers "F.Cu" "B.Cu")
		(net "GND")
	)
	(via
		(at 365.825532 -326.948292)
		(size 0.508)
		(drill 0.254)
		(layers "F.Cu" "B.Cu")
		(net "GND")
	)
	(via
		(at 122.923554 -407.00452)
		(size 0.4064)
		(drill 0.2032)
		(layers "F.Cu" "B.Cu")
		(net "GND")
	)
	(via
		(at 289.250882 -306.96662)
		(size 0.4572)
		(drill 0.2032)
		(layers "F.Cu" "B.Cu")
		(net "GND")
	)
	(via
		(at 262.519414 -199.01662)
		(size 0.4572)
		(drill 0.2032)
		(layers "F.Cu" "B.Cu")
		(net "GND")
	)
	(via
		(at 264.729214 -309.51678)
		(size 0.4572)
		(drill 0.2032)
		(layers "F.Cu" "B.Cu")
		(net "GND")
	)
	(via
		(at 172.795946 -306.116736)
		(size 0.4572)
		(drill 0.2032)
		(layers "F.Cu" "B.Cu")
		(net "GND")
	)
	(via
		(at 102.834694 -248.658126)
		(size 0.4572)
		(drill 0.2032)
		(layers "F.Cu" "B.Cu")
		(net "GND")
	)
	(via
		(at 156.355542 -46.223936)
		(size 0.508)
		(drill 0.254)
		(layers "F.Cu" "B.Cu")
		(net "GND")
	)
	(via
		(at 159.918146 -309.51678)
		(size 0.4572)
		(drill 0.2032)
		(layers "F.Cu" "B.Cu")
		(net "GND")
	)
	(via
		(at 131.015994 -269.38351)
		(size 0.4572)
		(drill 0.2032)
		(layers "F.Cu" "B.Cu")
		(net "GND")
	)
	(via
		(at 334.099408 -49.650396)
		(size 0.4572)
		(drill 0.2032)
		(layers "F.Cu" "B.Cu")
		(net "GND")
	)
	(via
		(at 460.664814 -317.166752)
		(size 0.4572)
		(drill 0.2032)
		(layers "F.Cu" "B.Cu")
		(net "GND")
	)
	(via
		(at 354.881434 -219.506038)
		(size 0.4572)
		(drill 0.2032)
		(layers "F.Cu" "B.Cu")
		(net "GND")
	)
	(via
		(at 377.076462 -271.011396)
		(size 0.4572)
		(drill 0.2032)
		(layers "F.Cu" "B.Cu")
		(net "GND")
	)
	(via
		(at 355.461062 -271.011396)
		(size 0.4572)
		(drill 0.2032)
		(layers "F.Cu" "B.Cu")
		(net "GND")
	)
	(via
		(at 347.473016 -253.919736)
		(size 0.4572)
		(drill 0.2032)
		(layers "F.Cu" "B.Cu")
		(net "GND")
	)
	(via
		(at 137.594594 -262.872474)
		(size 0.4572)
		(drill 0.2032)
		(layers "F.Cu" "B.Cu")
		(net "GND")
	)
	(via
		(at 125.847348 -268.569694)
		(size 0.4572)
		(drill 0.2032)
		(layers "F.Cu" "B.Cu")
		(net "GND")
	)
	(via
		(at 195.427346 -203.266802)
		(size 0.4572)
		(drill 0.2032)
		(layers "F.Cu" "B.Cu")
		(net "GND")
	)
	(via
		(at 387.169152 -245.27256)
		(size 0.4572)
		(drill 0.2032)
		(layers "F.Cu" "B.Cu")
		(net "GND")
	)
	(via
		(at 427.045882 -238.116618)
		(size 0.4572)
		(drill 0.2032)
		(layers "F.Cu" "B.Cu")
		(net "GND")
	)
	(via
		(at 112.580166 -222.761556)
		(size 0.4572)
		(drill 0.2032)
		(layers "F.Cu" "B.Cu")
		(net "GND")
	)
	(via
		(at 75.87488 -10.164318)
		(size 0.508)
		(drill 0.254)
		(layers "F.Cu" "B.Cu")
		(net "GND")
	)
	(via
		(at 450.911214 -290.816792)
		(size 0.4572)
		(drill 0.2032)
		(layers "F.Cu" "B.Cu")
		(net "GND")
	)
	(via
		(at 190.093346 -195.616576)
		(size 0.4572)
		(drill 0.2032)
		(layers "F.Cu" "B.Cu")
		(net "GND")
	)
	(via
		(at 405.648414 -221.96679)
		(size 0.4572)
		(drill 0.2032)
		(layers "F.Cu" "B.Cu")
		(net "GND")
	)
	(via
		(at 296.794682 -316.316614)
		(size 0.4572)
		(drill 0.2032)
		(layers "F.Cu" "B.Cu")
		(net "GND")
	)
	(via
		(at 254.67056 -151.051768)
		(size 0.508)
		(drill 0.254)
		(layers "F.Cu" "B.Cu")
		(net "GND")
	)
	(via
		(at 438.033414 -307.816758)
		(size 0.4572)
		(drill 0.2032)
		(layers "F.Cu" "B.Cu")
		(net "GND")
	)
	(via
		(at 165.252146 -199.01662)
		(size 0.4572)
		(drill 0.2032)
		(layers "F.Cu" "B.Cu")
		(net "GND")
	)
	(via
		(at 335.255362 -283.219906)
		(size 0.4572)
		(drill 0.2032)
		(layers "F.Cu" "B.Cu")
		(net "GND")
	)
	(via
		(at 289.250882 -210.066636)
		(size 0.4572)
		(drill 0.2032)
		(layers "F.Cu" "B.Cu")
		(net "GND")
	)
	(via
		(at 179.12588 -131.280408)
		(size 0.508)
		(drill 0.254)
		(layers "F.Cu" "B.Cu")
		(net "GND")
	)
	(via
		(at 407.858214 -300.166786)
		(size 0.4572)
		(drill 0.2032)
		(layers "F.Cu" "B.Cu")
		(net "GND")
	)
	(via
		(at 174.460916 -11.100054)
		(size 0.508)
		(drill 0.254)
		(layers "F.Cu" "B.Cu")
		(net "GND")
	)
	(via
		(at 328.625708 -48.450246)
		(size 0.4572)
		(drill 0.2032)
		(layers "F.Cu" "B.Cu")
		(net "GND")
	)
	(via
		(at 14.579346 -214.316564)
		(size 0.4572)
		(drill 0.2032)
		(layers "F.Cu" "B.Cu")
		(net "GND")
	)
	(via
		(at 22.123146 -231.316784)
		(size 0.4572)
		(drill 0.2032)
		(layers "F.Cu" "B.Cu")
		(net "GND")
	)
	(via
		(at 417.997894 -172.328078)
		(size 0.49022)
		(drill 0.254)
		(layers "F.Cu" "B.Cu")
		(net "GND")
	)
	(via
		(at 306.548282 -306.96662)
		(size 0.4572)
		(drill 0.2032)
		(layers "F.Cu" "B.Cu")
		(net "GND")
	)
	(via
		(at 368.618262 -282.405836)
		(size 0.4572)
		(drill 0.2032)
		(layers "F.Cu" "B.Cu")
		(net "GND")
	)
	(via
		(at 296.1513 -410.903166)
		(size 0.508)
		(drill 0.254)
		(layers "F.Cu" "B.Cu")
		(net "GND")
	)
	(via
		(at 115.399566 -229.272846)
		(size 0.4572)
		(drill 0.2032)
		(layers "F.Cu" "B.Cu")
		(net "GND")
	)
	(via
		(at 55.259224 -150.00605)
		(size 0.49022)
		(drill 0.254)
		(layers "F.Cu" "B.Cu")
		(net "GND")
	)
	(via
		(at 14.579346 -240.666778)
		(size 0.4572)
		(drill 0.2032)
		(layers "F.Cu" "B.Cu")
		(net "GND")
	)
	(via
		(at 363.05363 -364.15853)
		(size 0.508)
		(drill 0.254)
		(layers "F.Cu" "B.Cu")
		(net "GND")
	)
	(via
		(at 184.439814 -213.46668)
		(size 0.4572)
		(drill 0.2032)
		(layers "F.Cu" "B.Cu")
		(net "GND")
	)
	(via
		(at 199.527414 -241.516662)
		(size 0.4572)
		(drill 0.2032)
		(layers "F.Cu" "B.Cu")
		(net "GND")
	)
	(via
		(at 207.071214 -230.466646)
		(size 0.4572)
		(drill 0.2032)
		(layers "F.Cu" "B.Cu")
		(net "GND")
	)
	(via
		(at 392.57097 -410.030168)
		(size 0.4064)
		(drill 0.2032)
		(layers "F.Cu" "B.Cu")
		(net "GND")
	)
	(via
		(at 432.379882 -277.216616)
		(size 0.4572)
		(drill 0.2032)
		(layers "F.Cu" "B.Cu")
		(net "GND")
	)
	(via
		(at 302.448214 -268.71676)
		(size 0.4572)
		(drill 0.2032)
		(layers "F.Cu" "B.Cu")
		(net "GND")
	)
	(via
		(at 376.21337 -353.146868)
		(size 0.508)
		(drill 0.254)
		(layers "F.Cu" "B.Cu")
		(net "GND")
	)
	(via
		(at 214.615014 -289.966654)
		(size 0.4572)
		(drill 0.2032)
		(layers "F.Cu" "B.Cu")
		(net "GND")
	)
	(via
		(at 105.061766 -226.017328)
		(size 0.4572)
		(drill 0.2032)
		(layers "F.Cu" "B.Cu")
		(net "GND")
	)
	(via
		(at 410.35732 -173.759368)
		(size 0.508)
		(drill 0.254)
		(layers "F.Cu" "B.Cu")
		(net "GND")
	)
	(via
		(at 20.346924 -9.424924)
		(size 0.508)
		(drill 0.254)
		(layers "F.Cu" "B.Cu")
		(net "GND")
	)
	(via
		(at 28.433014 -316.316614)
		(size 0.4572)
		(drill 0.2032)
		(layers "F.Cu" "B.Cu")
		(net "GND")
	)
	(via
		(at 18.679414 -232.166668)
		(size 0.4572)
		(drill 0.2032)
		(layers "F.Cu" "B.Cu")
		(net "GND")
	)
	(via
		(at 425.685204 -354.180394)
		(size 0.508)
		(drill 0.254)
		(layers "F.Cu" "B.Cu")
		(net "GND")
	)
	(via
		(at 326.571356 -409.396184)
		(size 0.4572)
		(drill 0.254)
		(layers "F.Cu" "B.Cu")
		(net "GND")
	)
	(via
		(at 299.004482 -215.166702)
		(size 0.4572)
		(drill 0.2032)
		(layers "F.Cu" "B.Cu")
		(net "GND")
	)
	(via
		(at 406.267158 -407.638504)
		(size 0.4572)
		(drill 0.254)
		(layers "F.Cu" "B.Cu")
		(net "GND")
	)
	(via
		(at 95.56623 -56.225948)
		(size 0.508)
		(drill 0.254)
		(layers "F.Cu" "B.Cu")
		(net "GND")
	)
	(via
		(at 413.986218 -149.312376)
		(size 0.508)
		(drill 0.254)
		(layers "F.Cu" "B.Cu")
		(net "GND")
	)
	(via
		(at 169.142664 -219.41663)
		(size 0.4572)
		(drill 0.2032)
		(layers "F.Cu" "B.Cu")
		(net "GND")
	)
	(via
		(at 350.762062 -284.033722)
		(size 0.4572)
		(drill 0.2032)
		(layers "F.Cu" "B.Cu")
		(net "GND")
	)
	(via
		(at 95.303594 -284.033722)
		(size 0.4572)
		(drill 0.2032)
		(layers "F.Cu" "B.Cu")
		(net "GND")
	)
	(via
		(at 161.579814 -272.966688)
		(size 0.4572)
		(drill 0.2032)
		(layers "F.Cu" "B.Cu")
		(net "GND")
	)
	(via
		(at 27.700732 -0.76454)
		(size 0.508)
		(drill 0.254)
		(layers "F.Cu" "B.Cu")
		(net "GND")
	)
	(via
		(at 276.373082 -305.266598)
		(size 0.4572)
		(drill 0.2032)
		(layers "F.Cu" "B.Cu")
		(net "GND")
	)
	(via
		(at 257.102356 -36.023804)
		(size 0.508)
		(drill 0.254)
		(layers "F.Cu" "B.Cu")
		(net "GND")
	)
	(via
		(at 340.250018 -427.851316)
		(size 0.4572)
		(drill 0.2032)
		(layers "F.Cu" "B.Cu")
		(net "GND")
	)
	(via
		(at 195.427346 -285.716726)
		(size 0.4572)
		(drill 0.2032)
		(layers "F.Cu" "B.Cu")
		(net "GND")
	)
	(via
		(at 237.33252 -387.37794)
		(size 0.508)
		(drill 0.254)
		(layers "F.Cu" "B.Cu")
		(net "GND")
	)
	(via
		(at 87.30488 -101.759512)
		(size 0.508)
		(drill 0.254)
		(layers "F.Cu" "B.Cu")
		(net "GND")
	)
	(via
		(at 306.548282 -308.666642)
		(size 0.4572)
		(drill 0.2032)
		(layers "F.Cu" "B.Cu")
		(net "GND")
	)
	(via
		(at 11.135614 -245.76659)
		(size 0.4572)
		(drill 0.2032)
		(layers "F.Cu" "B.Cu")
		(net "GND")
	)
	(via
		(at 121.508266 -226.831144)
		(size 0.4572)
		(drill 0.2032)
		(layers "F.Cu" "B.Cu")
		(net "GND")
	)
	(via
		(at 179.105814 -258.516628)
		(size 0.4572)
		(drill 0.2032)
		(layers "F.Cu" "B.Cu")
		(net "GND")
	)
	(via
		(at 381.775462 -280.778204)
		(size 0.4572)
		(drill 0.2032)
		(layers "F.Cu" "B.Cu")
		(net "GND")
	)
	(via
		(at 404.920958 -404.51786)
		(size 0.4572)
		(drill 0.254)
		(layers "F.Cu" "B.Cu")
		(net "GND")
	)
	(via
		(at 121.577354 -400.858228)
		(size 0.4064)
		(drill 0.2032)
		(layers "F.Cu" "B.Cu")
		(net "GND")
	)
	(via
		(at 115.399566 -226.017328)
		(size 0.4572)
		(drill 0.2032)
		(layers "F.Cu" "B.Cu")
		(net "GND")
	)
	(via
		(at 455.011282 -241.516662)
		(size 0.4572)
		(drill 0.2032)
		(layers "F.Cu" "B.Cu")
		(net "GND")
	)
	(via
		(at 167.524684 -319.446656)
		(size 0.4572)
		(drill 0.2032)
		(layers "F.Cu" "B.Cu")
		(net "GND")
	)
	(via
		(at 130.132074 -407.00452)
		(size 0.4064)
		(drill 0.2032)
		(layers "F.Cu" "B.Cu")
		(net "GND")
	)
	(via
		(at 287.360614 -283.166566)
		(size 0.4572)
		(drill 0.2032)
		(layers "F.Cu" "B.Cu")
		(net "GND")
	)
	(via
		(at 108.351066 -223.575626)
		(size 0.4572)
		(drill 0.2032)
		(layers "F.Cu" "B.Cu")
		(net "GND")
	)
	(via
		(at 439.923682 -226.216718)
		(size 0.4572)
		(drill 0.2032)
		(layers "F.Cu" "B.Cu")
		(net "GND")
	)
	(via
		(at 57.404762 -151.59228)
		(size 0.508)
		(drill 0.254)
		(layers "F.Cu" "B.Cu")
		(net "GND")
	)
	(via
		(at 324.29323 -31.9659)
		(size 0.49022)
		(drill 0.254)
		(layers "F.Cu" "B.Cu")
		(net "GND")
	)
	(via
		(at 289.250882 -235.566712)
		(size 0.4572)
		(drill 0.2032)
		(layers "F.Cu" "B.Cu")
		(net "GND")
	)
	(via
		(at 92.954348 -268.569694)
		(size 0.4572)
		(drill 0.2032)
		(layers "F.Cu" "B.Cu")
		(net "GND")
	)
	(via
		(at 416.81273 -403.883876)
		(size 0.4064)
		(drill 0.2032)
		(layers "F.Cu" "B.Cu")
		(net "GND")
	)
	(via
		(at 2.764536 -289.990022)
		(size 0.508)
		(drill 0.254)
		(layers "F.Cu" "B.Cu")
		(net "GND")
	)
	(via
		(at 38.45687 -9.424924)
		(size 0.508)
		(drill 0.254)
		(layers "F.Cu" "B.Cu")
		(net "GND")
	)
	(via
		(at 412.195772 -16.967454)
		(size 0.508)
		(drill 0.254)
		(layers "F.Cu" "B.Cu")
		(net "GND")
	)
	(via
		(at 172.514768 -397.320008)
		(size 0.508)
		(drill 0.254)
		(layers "F.Cu" "B.Cu")
		(net "GND")
	)
	(via
		(at 262.519414 -258.516628)
		(size 0.4572)
		(drill 0.2032)
		(layers "F.Cu" "B.Cu")
		(net "GND")
	)
	(via
		(at 294.904414 -261.916672)
		(size 0.4572)
		(drill 0.2032)
		(layers "F.Cu" "B.Cu")
		(net "GND")
	)
	(via
		(at 89.194894 -283.219906)
		(size 0.4572)
		(drill 0.2032)
		(layers "F.Cu" "B.Cu")
		(net "GND")
	)
	(via
		(at 274.163282 -305.266598)
		(size 0.4572)
		(drill 0.2032)
		(layers "F.Cu" "B.Cu")
		(net "GND")
	)
	(via
		(at 462.555082 -266.1666)
		(size 0.4572)
		(drill 0.2032)
		(layers "F.Cu" "B.Cu")
		(net "GND")
	)
	(via
		(at 458.455014 -236.416596)
		(size 0.4572)
		(drill 0.2032)
		(layers "F.Cu" "B.Cu")
		(net "GND")
	)
	(via
		(at 354.490274 -183.93029)
		(size 0.508)
		(drill 0.254)
		(layers "F.Cu" "B.Cu")
		(net "GND")
	)
	(via
		(at 374.257316 -280.778204)
		(size 0.4572)
		(drill 0.2032)
		(layers "F.Cu" "B.Cu")
		(net "GND")
	)
	(via
		(at 76.250038 -437.49976)
		(size 0.4572)
		(drill 0.2032)
		(layers "F.Cu" "B.Cu")
		(net "GND")
	)
	(via
		(at 172.795946 -197.316598)
		(size 0.4572)
		(drill 0.2032)
		(layers "F.Cu" "B.Cu")
		(net "GND")
	)
	(via
		(at 435.823614 -281.466798)
		(size 0.4572)
		(drill 0.2032)
		(layers "F.Cu" "B.Cu")
		(net "GND")
	)
	(via
		(at 11.135614 -301.01667)
		(size 0.4572)
		(drill 0.2032)
		(layers "F.Cu" "B.Cu")
		(net "GND")
	)
	(via
		(at 415.402014 -197.316598)
		(size 0.4572)
		(drill 0.2032)
		(layers "F.Cu" "B.Cu")
		(net "GND")
	)
	(via
		(at 398.794478 -401.492212)
		(size 0.4572)
		(drill 0.254)
		(layers "F.Cu" "B.Cu")
		(net "GND")
	)
	(via
		(at 378.697998 -409.396184)
		(size 0.4572)
		(drill 0.254)
		(layers "F.Cu" "B.Cu")
		(net "GND")
	)
	(via
		(at 443.367414 -292.516814)
		(size 0.4572)
		(drill 0.2032)
		(layers "F.Cu" "B.Cu")
		(net "GND")
	)
	(via
		(at 106.421428 -103.593138)
		(size 0.508)
		(drill 0.254)
		(layers "F.Cu" "B.Cu")
		(net "GND")
	)
	(via
		(at 131.547108 -12.495276)
		(size 0.508)
		(drill 0.254)
		(layers "F.Cu" "B.Cu")
		(net "GND")
	)
	(via
		(at 51.064414 -269.566644)
		(size 0.4572)
		(drill 0.2032)
		(layers "F.Cu" "B.Cu")
		(net "GND")
	)
	(via
		(at 253.92888 -130.266948)
		(size 0.508)
		(drill 0.254)
		(layers "F.Cu" "B.Cu")
		(net "GND")
	)
	(via
		(at 403.116542 -400.224244)
		(size 0.4572)
		(drill 0.254)
		(layers "F.Cu" "B.Cu")
		(net "GND")
	)
	(via
		(at 56.094122 -109.221016)
		(size 0.508)
		(drill 0.254)
		(layers "F.Cu" "B.Cu")
		(net "GND")
	)
	(via
		(at 349.352616 -279.964134)
		(size 0.4572)
		(drill 0.2032)
		(layers "F.Cu" "B.Cu")
		(net "GND")
	)
	(via
		(at 63.250064 -429.147224)
		(size 0.4572)
		(drill 0.2032)
		(layers "F.Cu" "B.Cu")
		(net "GND")
	)
	(via
		(at 180.955696 -112.57534)
		(size 0.4572)
		(drill 0.254)
		(layers "F.Cu" "B.Cu")
		(net "GND")
	)
	(via
		(at 20.889214 -247.466612)
		(size 0.4572)
		(drill 0.2032)
		(layers "F.Cu" "B.Cu")
		(net "GND")
	)
	(via
		(at 195.427346 -258.516628)
		(size 0.4572)
		(drill 0.2032)
		(layers "F.Cu" "B.Cu")
		(net "GND")
	)
	(via
		(at 439.923682 -295.916604)
		(size 0.4572)
		(drill 0.2032)
		(layers "F.Cu" "B.Cu")
		(net "GND")
	)
	(via
		(at 218.52763 -130.317748)
		(size 0.508)
		(drill 0.254)
		(layers "F.Cu" "B.Cu")
		(net "GND")
	)
	(via
		(at 366.372902 -257.692906)
		(size 0.4572)
		(drill 0.2032)
		(layers "F.Cu" "B.Cu")
		(net "GND")
	)
	(via
		(at 153.194766 -407.638504)
		(size 0.4572)
		(drill 0.254)
		(layers "F.Cu" "B.Cu")
		(net "GND")
	)
	(via
		(at 107.347766 -331.780896)
		(size 0.49022)
		(drill 0.254)
		(layers "F.Cu" "B.Cu")
		(net "GND")
	)
	(via
		(at 199.527414 -258.516628)
		(size 0.4572)
		(drill 0.2032)
		(layers "F.Cu" "B.Cu")
		(net "GND")
	)
	(via
		(at 210.54314 -340.79815)
		(size 0.508)
		(drill 0.254)
		(layers "F.Cu" "B.Cu")
		(net "GND")
	)
	(via
		(at 89.085166 -222.761556)
		(size 0.4572)
		(drill 0.2032)
		(layers "F.Cu" "B.Cu")
		(net "GND")
	)
	(via
		(at 411.958282 -295.916604)
		(size 0.4572)
		(drill 0.2032)
		(layers "F.Cu" "B.Cu")
		(net "GND")
	)
	(via
		(at 348.882462 -284.033722)
		(size 0.4572)
		(drill 0.2032)
		(layers "F.Cu" "B.Cu")
		(net "GND")
	)
	(via
		(at 33.767014 -306.96662)
		(size 0.4572)
		(drill 0.2032)
		(layers "F.Cu" "B.Cu")
		(net "GND")
	)
	(via
		(at 191.983614 -272.966688)
		(size 0.4572)
		(drill 0.2032)
		(layers "F.Cu" "B.Cu")
		(net "GND")
	)
	(via
		(at 167.461946 -283.166566)
		(size 0.4572)
		(drill 0.2032)
		(layers "F.Cu" "B.Cu")
		(net "GND")
	)
	(via
		(at 277.607014 -242.3668)
		(size 0.4572)
		(drill 0.2032)
		(layers "F.Cu" "B.Cu")
		(net "GND")
	)
	(via
		(at 56.867044 -10.16508)
		(size 0.508)
		(drill 0.254)
		(layers "F.Cu" "B.Cu")
		(net "GND")
	)
	(via
		(at 101.412548 -279.964134)
		(size 0.4572)
		(drill 0.2032)
		(layers "F.Cu" "B.Cu")
		(net "GND")
	)
	(via
		(at 15.336266 -16.978376)
		(size 0.508)
		(drill 0.254)
		(layers "F.Cu" "B.Cu")
		(net "GND")
	)
	(via
		(at 407.858214 -229.616762)
		(size 0.4572)
		(drill 0.2032)
		(layers "F.Cu" "B.Cu")
		(net "GND")
	)
	(via
		(at 377.90628 -230.086662)
		(size 0.4572)
		(drill 0.2032)
		(layers "F.Cu" "B.Cu")
		(net "GND")
	)
	(via
		(at 65.25006 -432.451256)
		(size 0.4572)
		(drill 0.2032)
		(layers "F.Cu" "B.Cu")
		(net "GND")
	)
	(via
		(at 121.617994 -282.405836)
		(size 0.4572)
		(drill 0.2032)
		(layers "F.Cu" "B.Cu")
		(net "GND")
	)
	(via
		(at 289.250882 -294.216582)
		(size 0.4572)
		(drill 0.2032)
		(layers "F.Cu" "B.Cu")
		(net "GND")
	)
	(via
		(at 88.856566 -336.765392)
		(size 0.49022)
		(drill 0.254)
		(layers "F.Cu" "B.Cu")
		(net "GND")
	)
	(via
		(at 62.051946 -260.21665)
		(size 0.4572)
		(drill 0.2032)
		(layers "F.Cu" "B.Cu")
		(net "GND")
	)
	(via
		(at 153.652982 -404.51786)
		(size 0.4572)
		(drill 0.254)
		(layers "F.Cu" "B.Cu")
		(net "GND")
	)
	(via
		(at 28.433014 -235.566712)
		(size 0.4572)
		(drill 0.2032)
		(layers "F.Cu" "B.Cu")
		(net "GND")
	)
	(via
		(at 430.489614 -223.666558)
		(size 0.4572)
		(drill 0.2032)
		(layers "F.Cu" "B.Cu")
		(net "GND")
	)
	(via
		(at 452.73468 -112.772698)
		(size 0.508)
		(drill 0.254)
		(layers "F.Cu" "B.Cu")
		(net "GND")
	)
	(via
		(at 450.911214 -199.01662)
		(size 0.4572)
		(drill 0.2032)
		(layers "F.Cu" "B.Cu")
		(net "GND")
	)
	(via
		(at 7.035546 -236.416596)
		(size 0.4572)
		(drill 0.2032)
		(layers "F.Cu" "B.Cu")
		(net "GND")
	)
	(via
		(at 370.388134 -246.364506)
		(size 0.4572)
		(drill 0.2032)
		(layers "F.Cu" "B.Cu")
		(net "GND")
	)
	(via
		(at 56.915558 -359.91165)
		(size 0.508)
		(drill 0.254)
		(layers "F.Cu" "B.Cu")
		(net "GND")
	)
	(via
		(at 199.527414 -228.766624)
		(size 0.4572)
		(drill 0.2032)
		(layers "F.Cu" "B.Cu")
		(net "GND")
	)
	(via
		(at 368.778028 -333.355188)
		(size 0.49022)
		(drill 0.254)
		(layers "F.Cu" "B.Cu")
		(net "GND")
	)
	(via
		(at 439.923682 -312.91657)
		(size 0.4572)
		(drill 0.2032)
		(layers "F.Cu" "B.Cu")
		(net "GND")
	)
	(via
		(at 52.298346 -238.966756)
		(size 0.4572)
		(drill 0.2032)
		(layers "F.Cu" "B.Cu")
		(net "GND")
	)
	(via
		(at 52.082446 -292.516814)
		(size 0.4572)
		(drill 0.2032)
		(layers "F.Cu" "B.Cu")
		(net "GND")
	)
	(via
		(at 422.945814 -301.866808)
		(size 0.4572)
		(drill 0.2032)
		(layers "F.Cu" "B.Cu")
		(net "GND")
	)
	(via
		(at 453.0852 -59.629548)
		(size 0.508)
		(drill 0.254)
		(layers "F.Cu" "B.Cu")
		(net "GND")
	)
	(via
		(at 418.432742 -404.51786)
		(size 0.4572)
		(drill 0.254)
		(layers "F.Cu" "B.Cu")
		(net "GND")
	)
	(via
		(at 51.064414 -204.116686)
		(size 0.4572)
		(drill 0.2032)
		(layers "F.Cu" "B.Cu")
		(net "GND")
	)
	(via
		(at 157.349952 -428.851314)
		(size 0.4572)
		(drill 0.2032)
		(layers "F.Cu" "B.Cu")
		(net "GND")
	)
	(via
		(at 439.923682 -264.466578)
		(size 0.4572)
		(drill 0.2032)
		(layers "F.Cu" "B.Cu")
		(net "GND")
	)
	(via
		(at 184.439814 -219.41663)
		(size 0.4572)
		(drill 0.2032)
		(layers "F.Cu" "B.Cu")
		(net "GND")
	)
	(via
		(at 106.111548 -265.314176)
		(size 0.4572)
		(drill 0.2032)
		(layers "F.Cu" "B.Cu")
		(net "GND")
	)
	(via
		(at 184.439814 -264.466578)
		(size 0.4572)
		(drill 0.2032)
		(layers "F.Cu" "B.Cu")
		(net "GND")
	)
	(via
		(at 252.27407 -44.209462)
		(size 0.508)
		(drill 0.254)
		(layers "F.Cu" "B.Cu")
		(net "GND")
	)
	(via
		(at 417.292282 -205.816708)
		(size 0.4572)
		(drill 0.2032)
		(layers "F.Cu" "B.Cu")
		(net "GND")
	)
	(via
		(at 410.660596 -19.759422)
		(size 0.508)
		(drill 0.254)
		(layers "F.Cu" "B.Cu")
		(net "GND")
	)
	(via
		(at 346.063316 -259.616956)
		(size 0.4572)
		(drill 0.2032)
		(layers "F.Cu" "B.Cu")
		(net "GND")
	)
	(via
		(at 409.69692 -167.731948)
		(size 0.508)
		(drill 0.254)
		(layers "F.Cu" "B.Cu")
		(net "GND")
	)
	(via
		(at 338.250022 -434.899562)
		(size 0.4572)
		(drill 0.2032)
		(layers "F.Cu" "B.Cu")
		(net "GND")
	)
	(via
		(at 270.063214 -220.266768)
		(size 0.4572)
		(drill 0.2032)
		(layers "F.Cu" "B.Cu")
		(net "GND")
	)
	(via
		(at 347.363034 -222.761556)
		(size 0.4572)
		(drill 0.2032)
		(layers "F.Cu" "B.Cu")
		(net "GND")
	)
	(via
		(at 242.871752 -131.17068)
		(size 0.508)
		(drill 0.254)
		(layers "F.Cu" "B.Cu")
		(net "GND")
	)
	(via
		(at 363.919516 -274.266914)
		(size 0.4572)
		(drill 0.2032)
		(layers "F.Cu" "B.Cu")
		(net "GND")
	)
	(via
		(at 411.958282 -221.116652)
		(size 0.4572)
		(drill 0.2032)
		(layers "F.Cu" "B.Cu")
		(net "GND")
	)
	(via
		(at 43.754548 -351.612708)
		(size 0.49022)
		(drill 0.254)
		(layers "F.Cu" "B.Cu")
		(net "GND")
	)
	(via
		(at 182.675276 -49.887886)
		(size 0.508)
		(drill 0.254)
		(layers "F.Cu" "B.Cu")
		(net "GND")
	)
	(via
		(at 73.679558 -187.89269)
		(size 0.508)
		(drill 0.254)
		(layers "F.Cu" "B.Cu")
		(net "GND")
	)
	(via
		(at 259.06349 -51.646582)
		(size 0.508)
		(drill 0.254)
		(layers "F.Cu" "B.Cu")
		(net "GND")
	)
	(via
		(at 58.608214 -196.466714)
		(size 0.4572)
		(drill 0.2032)
		(layers "F.Cu" "B.Cu")
		(net "GND")
	)
	(via
		(at 137.014966 -235.783882)
		(size 0.4318)
		(drill 0.2032)
		(layers "F.Cu" "B.Cu")
		(net "GND")
	)
	(via
		(at 168.431972 -421.527478)
		(size 0.508)
		(drill 0.254)
		(layers "F.Cu" "B.Cu")
		(net "GND")
	)
	(via
		(at 167.461946 -248.31675)
		(size 0.4572)
		(drill 0.2032)
		(layers "F.Cu" "B.Cu")
		(net "GND")
	)
	(via
		(at 63.942214 -301.01667)
		(size 0.4572)
		(drill 0.2032)
		(layers "F.Cu" "B.Cu")
		(net "GND")
	)
	(via
		(at 296.794682 -264.466578)
		(size 0.4572)
		(drill 0.2032)
		(layers "F.Cu" "B.Cu")
		(net "GND")
	)
	(via
		(at 240.522252 -251.755148)
		(size 0.508)
		(drill 0.254)
		(layers "F.Cu" "B.Cu")
		(net "GND")
	)
	(via
		(at 95.663766 -219.506038)
		(size 0.4572)
		(drill 0.2032)
		(layers "F.Cu" "B.Cu")
		(net "GND")
	)
	(via
		(at 31.876746 -212.616796)
		(size 0.4572)
		(drill 0.2032)
		(layers "F.Cu" "B.Cu")
		(net "GND")
	)
	(via
		(at 100.942648 -256.361438)
		(size 0.4572)
		(drill 0.2032)
		(layers "F.Cu" "B.Cu")
		(net "GND")
	)
	(via
		(at 136.075166 -247.178322)
		(size 0.4318)
		(drill 0.2032)
		(layers "F.Cu" "B.Cu")
		(net "GND")
	)
	(via
		(at 82.250026 -432.451256)
		(size 0.4572)
		(drill 0.2032)
		(layers "F.Cu" "B.Cu")
		(net "GND")
	)
	(via
		(at 48.767238 -407.00452)
		(size 0.4064)
		(drill 0.2032)
		(layers "F.Cu" "B.Cu")
		(net "GND")
	)
	(via
		(at 39.552372 -352.397822)
		(size 0.49022)
		(drill 0.254)
		(layers "F.Cu" "B.Cu")
		(net "GND")
	)
	(via
		(at 312.928 -63.076328)
		(size 0.508)
		(drill 0.254)
		(layers "F.Cu" "B.Cu")
		(net "GND")
	)
	(via
		(at 429.465486 -354.06838)
		(size 0.508)
		(drill 0.254)
		(layers "F.Cu" "B.Cu")
		(net "GND")
	)
	(via
		(at 455.011282 -261.066788)
		(size 0.4572)
		(drill 0.2032)
		(layers "F.Cu" "B.Cu")
		(net "GND")
	)
	(via
		(at 207.071214 -299.316648)
		(size 0.4572)
		(drill 0.2032)
		(layers "F.Cu" "B.Cu")
		(net "GND")
	)
	(via
		(at 405.64689 -7.215124)
		(size 0.508)
		(drill 0.254)
		(layers "F.Cu" "B.Cu")
		(net "GND")
	)
	(via
		(at 169.352214 -267.866622)
		(size 0.4572)
		(drill 0.2032)
		(layers "F.Cu" "B.Cu")
		(net "GND")
	)
	(via
		(at 384.233928 -344.90533)
		(size 0.49022)
		(drill 0.254)
		(layers "F.Cu" "B.Cu")
		(net "GND")
	)
	(via
		(at 422.945814 -300.166786)
		(size 0.4572)
		(drill 0.2032)
		(layers "F.Cu" "B.Cu")
		(net "GND")
	)
	(via
		(at 54.724046 -313.766708)
		(size 0.4572)
		(drill 0.2032)
		(layers "F.Cu" "B.Cu")
		(net "GND")
	)
	(via
		(at 131.015994 -264.50036)
		(size 0.4572)
		(drill 0.2032)
		(layers "F.Cu" "B.Cu")
		(net "GND")
	)
	(via
		(at 99.532948 -276.708616)
		(size 0.4572)
		(drill 0.2032)
		(layers "F.Cu" "B.Cu")
		(net "GND")
	)
	(via
		(at 191.983614 -232.166668)
		(size 0.4572)
		(drill 0.2032)
		(layers "F.Cu" "B.Cu")
		(net "GND")
	)
	(via
		(at 190.093346 -281.466798)
		(size 0.4572)
		(drill 0.2032)
		(layers "F.Cu" "B.Cu")
		(net "GND")
	)
	(via
		(at 353.581462 -271.011396)
		(size 0.4572)
		(drill 0.2032)
		(layers "F.Cu" "B.Cu")
		(net "GND")
	)
	(via
		(at 434.589682 -266.1666)
		(size 0.4572)
		(drill 0.2032)
		(layers "F.Cu" "B.Cu")
		(net "GND")
	)
	(via
		(at 270.063214 -201.56678)
		(size 0.4572)
		(drill 0.2032)
		(layers "F.Cu" "B.Cu")
		(net "GND")
	)
	(via
		(at 381.40005 -407.00452)
		(size 0.4064)
		(drill 0.2032)
		(layers "F.Cu" "B.Cu")
		(net "GND")
	)
	(via
		(at 430.489614 -317.166752)
		(size 0.4572)
		(drill 0.2032)
		(layers "F.Cu" "B.Cu")
		(net "GND")
	)
	(via
		(at 329.634596 -406.370536)
		(size 0.4572)
		(drill 0.254)
		(layers "F.Cu" "B.Cu")
		(net "GND")
	)
	(via
		(at 127.616712 -245.55069)
		(size 0.4572)
		(drill 0.2032)
		(layers "F.Cu" "B.Cu")
		(net "GND")
	)
	(via
		(at 90.667586 -404.51786)
		(size 0.4572)
		(drill 0.254)
		(layers "F.Cu" "B.Cu")
		(net "GND")
	)
	(via
		(at 58.608214 -198.166736)
		(size 0.4572)
		(drill 0.2032)
		(layers "F.Cu" "B.Cu")
		(net "GND")
	)
	(via
		(at 101.412548 -257.175254)
		(size 0.4572)
		(drill 0.2032)
		(layers "F.Cu" "B.Cu")
		(net "GND")
	)
	(via
		(at 363.448092 -332.570074)
		(size 0.49022)
		(drill 0.254)
		(layers "F.Cu" "B.Cu")
		(net "GND")
	)
	(via
		(at 26.223214 -305.266598)
		(size 0.4572)
		(drill 0.2032)
		(layers "F.Cu" "B.Cu")
		(net "GND")
	)
	(via
		(at 306.83454 -429.632618)
		(size 0.508)
		(drill 0.254)
		(layers "F.Cu" "B.Cu")
		(net "GND")
	)
	(via
		(at 218.677998 -18.256758)
		(size 0.508)
		(drill 0.254)
		(layers "F.Cu" "B.Cu")
		(net "GND")
	)
	(via
		(at 419.705282 -294.216582)
		(size 0.4572)
		(drill 0.2032)
		(layers "F.Cu" "B.Cu")
		(net "GND")
	)
	(via
		(at 11.438636 -114.072924)
		(size 0.508)
		(drill 0.254)
		(layers "F.Cu" "B.Cu")
		(net "GND")
	)
	(via
		(at 29.346906 -12.37488)
		(size 0.508)
		(drill 0.254)
		(layers "F.Cu" "B.Cu")
		(net "GND")
	)
	(via
		(at 28.433014 -312.91657)
		(size 0.4572)
		(drill 0.2032)
		(layers "F.Cu" "B.Cu")
		(net "GND")
	)
	(via
		(at 176.896014 -305.266598)
		(size 0.4572)
		(drill 0.2032)
		(layers "F.Cu" "B.Cu")
		(net "GND")
	)
	(via
		(at 110.230666 -217.064336)
		(size 0.4572)
		(drill 0.2032)
		(layers "F.Cu" "B.Cu")
		(net "GND")
	)
	(via
		(at 388.493 -32.918908)
		(size 0.508)
		(drill 0.254)
		(layers "F.Cu" "B.Cu")
		(net "GND")
	)
	(via
		(at 366.738916 -275.8948)
		(size 0.4572)
		(drill 0.2032)
		(layers "F.Cu" "B.Cu")
		(net "GND")
	)
	(via
		(at 73.908158 -400.858228)
		(size 0.4064)
		(drill 0.2032)
		(layers "F.Cu" "B.Cu")
		(net "GND")
	)
	(via
		(at 374.88749 -365.665258)
		(size 0.508)
		(drill 0.254)
		(layers "F.Cu" "B.Cu")
		(net "GND")
	)
	(via
		(at 268.829282 -219.41663)
		(size 0.4572)
		(drill 0.2032)
		(layers "F.Cu" "B.Cu")
		(net "GND")
	)
	(via
		(at 342.303862 -269.38351)
		(size 0.4572)
		(drill 0.2032)
		(layers "F.Cu" "B.Cu")
		(net "GND")
	)
	(via
		(at 96.133412 -239.853216)
		(size 0.4572)
		(drill 0.2032)
		(layers "F.Cu" "B.Cu")
		(net "GND")
	)
	(via
		(at 94.250764 -101.759512)
		(size 0.508)
		(drill 0.254)
		(layers "F.Cu" "B.Cu")
		(net "GND")
	)
	(via
		(at 120.11533 -441.225432)
		(size 0.508)
		(drill 0.254)
		(layers "F.Cu" "B.Cu")
		(net "GND")
	)
	(via
		(at 386.834634 -221.133924)
		(size 0.4572)
		(drill 0.2032)
		(layers "F.Cu" "B.Cu")
		(net "GND")
	)
	(via
		(at 342.735154 -42.341292)
		(size 0.4572)
		(drill 0.2032)
		(layers "F.Cu" "B.Cu")
		(net "GND")
	)
	(via
		(at 363.322616 -248.642632)
		(size 0.4572)
		(drill 0.2032)
		(layers "F.Cu" "B.Cu")
		(net "GND")
	)
	(via
		(at 426.477684 -360.148378)
		(size 0.49022)
		(drill 0.254)
		(layers "F.Cu" "B.Cu")
		(net "GND")
	)
	(via
		(at 165.447726 -410.664152)
		(size 0.4572)
		(drill 0.254)
		(layers "F.Cu" "B.Cu")
		(net "GND")
	)
	(via
		(at 175.005746 -273.587972)
		(size 0.4572)
		(drill 0.2032)
		(layers "F.Cu" "B.Cu")
		(net "GND")
	)
	(via
		(at 207.071214 -224.516696)
		(size 0.4572)
		(drill 0.2032)
		(layers "F.Cu" "B.Cu")
		(net "GND")
	)
	(via
		(at 413.962596 -17.601438)
		(size 0.508)
		(drill 0.254)
		(layers "F.Cu" "B.Cu")
		(net "GND")
	)
	(via
		(at 453.121014 -289.11677)
		(size 0.4572)
		(drill 0.2032)
		(layers "F.Cu" "B.Cu")
		(net "GND")
	)
	(via
		(at 35.976814 -198.166736)
		(size 0.4572)
		(drill 0.2032)
		(layers "F.Cu" "B.Cu")
		(net "GND")
	)
	(via
		(at 346.667836 -401.492212)
		(size 0.4572)
		(drill 0.254)
		(layers "F.Cu" "B.Cu")
		(net "GND")
	)
	(via
		(at 129.496566 -230.900478)
		(size 0.4572)
		(drill 0.2032)
		(layers "F.Cu" "B.Cu")
		(net "GND")
	)
	(via
		(at 104.231694 -289.807142)
		(size 0.4572)
		(drill 0.2032)
		(layers "F.Cu" "B.Cu")
		(net "GND")
	)
	(via
		(at 134.665466 -223.575626)
		(size 0.4572)
		(drill 0.2032)
		(layers "F.Cu" "B.Cu")
		(net "GND")
	)
	(via
		(at 382.03505 -400.858228)
		(size 0.4064)
		(drill 0.2032)
		(layers "F.Cu" "B.Cu")
		(net "GND")
	)
	(via
		(at 372.26748 -239.853216)
		(size 0.4572)
		(drill 0.2032)
		(layers "F.Cu" "B.Cu")
		(net "GND")
	)
	(via
		(at 92.374466 -244.73662)
		(size 0.4572)
		(drill 0.2032)
		(layers "F.Cu" "B.Cu")
		(net "GND")
	)
	(via
		(at 31.152084 -323.434456)
		(size 0.4572)
		(drill 0.2032)
		(layers "F.Cu" "B.Cu")
		(net "GND")
	)
	(via
		(at 58.608214 -258.516628)
		(size 0.4572)
		(drill 0.2032)
		(layers "F.Cu" "B.Cu")
		(net "GND")
	)
	(via
		(at 61.250068 -426.54728)
		(size 0.4572)
		(drill 0.2032)
		(layers "F.Cu" "B.Cu")
		(net "GND")
	)
	(via
		(at 44.754546 -265.316716)
		(size 0.4572)
		(drill 0.2032)
		(layers "F.Cu" "B.Cu")
		(net "GND")
	)
	(via
		(at 450.911214 -221.96679)
		(size 0.4572)
		(drill 0.2032)
		(layers "F.Cu" "B.Cu")
		(net "GND")
	)
	(via
		(at 236.599984 -244.368828)
		(size 0.508)
		(drill 0.254)
		(layers "F.Cu" "B.Cu")
		(net "GND")
	)
	(via
		(at 60.551822 -153.54046)
		(size 0.508)
		(drill 0.254)
		(layers "F.Cu" "B.Cu")
		(net "GND")
	)
	(via
		(at 94.833694 -283.219906)
		(size 0.4572)
		(drill 0.2032)
		(layers "F.Cu" "B.Cu")
		(net "GND")
	)
	(via
		(at 257.185414 -204.96657)
		(size 0.4572)
		(drill 0.2032)
		(layers "F.Cu" "B.Cu")
		(net "GND")
	)
	(via
		(at 103.257604 -405.426672)
		(size 0.508)
		(drill 0.254)
		(layers "F.Cu" "B.Cu")
		(net "GND")
	)
	(via
		(at 276.373082 -301.01667)
		(size 0.4572)
		(drill 0.2032)
		(layers "F.Cu" "B.Cu")
		(net "GND")
	)
	(via
		(at 172.653198 -351.614994)
		(size 0.49022)
		(drill 0.254)
		(layers "F.Cu" "B.Cu")
		(net "GND")
	)
	(via
		(at 52.10429 -401.492212)
		(size 0.4572)
		(drill 0.254)
		(layers "F.Cu" "B.Cu")
		(net "GND")
	)
	(via
		(at 263.70788 -149.824948)
		(size 0.508)
		(drill 0.254)
		(layers "F.Cu" "B.Cu")
		(net "GND")
	)
	(via
		(at 358.41178 -407.233628)
		(size 0.508)
		(drill 0.254)
		(layers "F.Cu" "B.Cu")
		(net "GND")
	)
	(via
		(at 409.748482 -282.316682)
		(size 0.4572)
		(drill 0.2032)
		(layers "F.Cu" "B.Cu")
		(net "GND")
	)
	(via
		(at 96.733868 -338.86013)
		(size 0.508)
		(drill 0.254)
		(layers "F.Cu" "B.Cu")
		(net "GND")
	)
	(via
		(at 279.816814 -212.616796)
		(size 0.4572)
		(drill 0.2032)
		(layers "F.Cu" "B.Cu")
		(net "GND")
	)
	(via
		(at 210.514946 -306.116736)
		(size 0.4572)
		(drill 0.2032)
		(layers "F.Cu" "B.Cu")
		(net "GND")
	)
	(via
		(at 128.28397 -353.111054)
		(size 0.508)
		(drill 0.254)
		(layers "F.Cu" "B.Cu")
		(net "GND")
	)
	(via
		(at 434.57368 -20.869148)
		(size 0.508)
		(drill 0.254)
		(layers "F.Cu" "B.Cu")
		(net "GND")
	)
	(via
		(at 344.183462 -271.011396)
		(size 0.4572)
		(drill 0.2032)
		(layers "F.Cu" "B.Cu")
		(net "GND")
	)
	(via
		(at 335.255362 -265.314176)
		(size 0.4572)
		(drill 0.2032)
		(layers "F.Cu" "B.Cu")
		(net "GND")
	)
	(via
		(at 407.858214 -199.01662)
		(size 0.4572)
		(drill 0.2032)
		(layers "F.Cu" "B.Cu")
		(net "GND")
	)
	(via
		(at 88.250014 -429.147224)
		(size 0.4572)
		(drill 0.2032)
		(layers "F.Cu" "B.Cu")
		(net "GND")
	)
	(via
		(at 326.210168 -410.030168)
		(size 0.4064)
		(drill 0.2032)
		(layers "F.Cu" "B.Cu")
		(net "GND")
	)
	(via
		(at 272.273014 -272.116804)
		(size 0.4572)
		(drill 0.2032)
		(layers "F.Cu" "B.Cu")
		(net "GND")
	)
	(via
		(at 354.411534 -220.319854)
		(size 0.4572)
		(drill 0.2032)
		(layers "F.Cu" "B.Cu")
		(net "GND")
	)
	(via
		(at 372.377462 -261.244842)
		(size 0.4572)
		(drill 0.2032)
		(layers "F.Cu" "B.Cu")
		(net "GND")
	)
	(via
		(at 181.455822 -355.538278)
		(size 0.49022)
		(drill 0.254)
		(layers "F.Cu" "B.Cu")
		(net "GND")
	)
	(via
		(at 283.916882 -316.316614)
		(size 0.4572)
		(drill 0.2032)
		(layers "F.Cu" "B.Cu")
		(net "GND")
	)
	(via
		(at 259.075682 -301.01667)
		(size 0.4572)
		(drill 0.2032)
		(layers "F.Cu" "B.Cu")
		(net "GND")
	)
	(via
		(at 85.79993 -400.224244)
		(size 0.4572)
		(drill 0.254)
		(layers "F.Cu" "B.Cu")
		(net "GND")
	)
	(via
		(at 51.467004 -7.215124)
		(size 0.508)
		(drill 0.254)
		(layers "F.Cu" "B.Cu")
		(net "GND")
	)
	(via
		(at 44.754546 -231.316784)
		(size 0.4572)
		(drill 0.2032)
		(layers "F.Cu" "B.Cu")
		(net "GND")
	)
	(via
		(at 125.377194 -267.755878)
		(size 0.4572)
		(drill 0.2032)
		(layers "F.Cu" "B.Cu")
		(net "GND")
	)
	(via
		(at 101.772212 -249.620024)
		(size 0.4572)
		(drill 0.2032)
		(layers "F.Cu" "B.Cu")
		(net "GND")
	)
	(via
		(at 276.373082 -250.866656)
		(size 0.4572)
		(drill 0.2032)
		(layers "F.Cu" "B.Cu")
		(net "GND")
	)
	(via
		(at 289.250882 -200.716642)
		(size 0.4572)
		(drill 0.2032)
		(layers "F.Cu" "B.Cu")
		(net "GND")
	)
	(via
		(at 43.520614 -226.216718)
		(size 0.4572)
		(drill 0.2032)
		(layers "F.Cu" "B.Cu")
		(net "GND")
	)
	(via
		(at 133.255766 -222.761556)
		(size 0.4572)
		(drill 0.2032)
		(layers "F.Cu" "B.Cu")
		(net "GND")
	)
	(via
		(at 370.858034 -230.900478)
		(size 0.4572)
		(drill 0.2032)
		(layers "F.Cu" "B.Cu")
		(net "GND")
	)
	(via
		(at 270.063214 -315.46673)
		(size 0.4572)
		(drill 0.2032)
		(layers "F.Cu" "B.Cu")
		(net "GND")
	)
	(via
		(at 380.725934 -213.732618)
		(size 0.4572)
		(drill 0.2032)
		(layers "F.Cu" "B.Cu")
		(net "GND")
	)
	(via
		(at 54.3814 -176.168304)
		(size 0.508)
		(drill 0.254)
		(layers "F.Cu" "B.Cu")
		(net "GND")
	)
	(via
		(at 414.863534 -177.268378)
		(size 0.49022)
		(drill 0.254)
		(layers "F.Cu" "B.Cu")
		(net "GND")
	)
	(via
		(at 132.350002 -428.851314)
		(size 0.4572)
		(drill 0.2032)
		(layers "F.Cu" "B.Cu")
		(net "GND")
	)
	(via
		(at 344.950796 -409.396184)
		(size 0.4572)
		(drill 0.254)
		(layers "F.Cu" "B.Cu")
		(net "GND")
	)
	(via
		(at 369.088162 -283.219906)
		(size 0.4572)
		(drill 0.2032)
		(layers "F.Cu" "B.Cu")
		(net "GND")
	)
	(via
		(at 238.362998 -115.685316)
		(size 0.508)
		(drill 0.254)
		(layers "F.Cu" "B.Cu")
		(net "GND")
	)
	(via
		(at 214.615014 -303.566576)
		(size 0.4572)
		(drill 0.2032)
		(layers "F.Cu" "B.Cu")
		(net "GND")
	)
	(via
		(at 88.250014 -427.851316)
		(size 0.4572)
		(drill 0.2032)
		(layers "F.Cu" "B.Cu")
		(net "GND")
	)
	(via
		(at 336.285332 -37.141658)
		(size 0.49022)
		(drill 0.254)
		(layers "F.Cu" "B.Cu")
		(net "GND")
	)
	(via
		(at 121.762266 -114.92103)
		(size 0.508)
		(drill 0.254)
		(layers "F.Cu" "B.Cu")
		(net "GND")
	)
	(via
		(at 138.34999 -438.651396)
		(size 0.4572)
		(drill 0.2032)
		(layers "F.Cu" "B.Cu")
		(net "GND")
	)
	(via
		(at 194.193414 -210.066636)
		(size 0.4572)
		(drill 0.2032)
		(layers "F.Cu" "B.Cu")
		(net "GND")
	)
	(via
		(at 298.233338 -367.755932)
		(size 0.508)
		(drill 0.254)
		(layers "F.Cu" "B.Cu")
		(net "GND")
	)
	(via
		(at 416.808158 -4.95173)
		(size 0.508)
		(drill 0.254)
		(layers "F.Cu" "B.Cu")
		(net "GND")
	)
	(via
		(at 157.975046 -403.249892)
		(size 0.4572)
		(drill 0.254)
		(layers "F.Cu" "B.Cu")
		(net "GND")
	)
	(via
		(at 61.250068 -438.499758)
		(size 0.4572)
		(drill 0.2032)
		(layers "F.Cu" "B.Cu")
		(net "GND")
	)
	(via
		(at 386.369052 -340.977728)
		(size 0.49022)
		(drill 0.254)
		(layers "F.Cu" "B.Cu")
		(net "GND")
	)
	(via
		(at 44.754546 -268.71676)
		(size 0.4572)
		(drill 0.2032)
		(layers "F.Cu" "B.Cu")
		(net "GND")
	)
	(via
		(at 45.890688 -352.548698)
		(size 0.508)
		(drill 0.254)
		(layers "F.Cu" "B.Cu")
		(net "GND")
	)
	(via
		(at 136.545066 -220.319854)
		(size 0.4572)
		(drill 0.2032)
		(layers "F.Cu" "B.Cu")
		(net "GND")
	)
	(via
		(at 421.618156 -173.654974)
		(size 0.508)
		(drill 0.254)
		(layers "F.Cu" "B.Cu")
		(net "GND")
	)
	(via
		(at 337.604862 -287.28924)
		(size 0.4572)
		(drill 0.2032)
		(layers "F.Cu" "B.Cu")
		(net "GND")
	)
	(via
		(at 443.367414 -212.616796)
		(size 0.4572)
		(drill 0.2032)
		(layers "F.Cu" "B.Cu")
		(net "GND")
	)
	(via
		(at 268.840712 -66.323972)
		(size 0.508)
		(drill 0.254)
		(layers "F.Cu" "B.Cu")
		(net "GND")
	)
	(via
		(at 346.893134 -217.064336)
		(size 0.4572)
		(drill 0.2032)
		(layers "F.Cu" "B.Cu")
		(net "GND")
	)
	(via
		(at 214.615014 -258.516628)
		(size 0.4572)
		(drill 0.2032)
		(layers "F.Cu" "B.Cu")
		(net "GND")
	)
	(via
		(at 115.039394 -277.522432)
		(size 0.4572)
		(drill 0.2032)
		(layers "F.Cu" "B.Cu")
		(net "GND")
	)
	(via
		(at 343.149428 -326.910192)
		(size 0.508)
		(drill 0.254)
		(layers "F.Cu" "B.Cu")
		(net "GND")
	)
	(via
		(at 206.815436 -340.47811)
		(size 0.508)
		(drill 0.254)
		(layers "F.Cu" "B.Cu")
		(net "GND")
	)
	(via
		(at 180.70576 -364.97387)
		(size 0.508)
		(drill 0.254)
		(layers "F.Cu" "B.Cu")
		(net "GND")
	)
	(via
		(at 276.373082 -200.716642)
		(size 0.4572)
		(drill 0.2032)
		(layers "F.Cu" "B.Cu")
		(net "GND")
	)
	(via
		(at 89.195148 -255.547622)
		(size 0.4572)
		(drill 0.2032)
		(layers "F.Cu" "B.Cu")
		(net "GND")
	)
	(via
		(at 68.76669 -409.396184)
		(size 0.4572)
		(drill 0.254)
		(layers "F.Cu" "B.Cu")
		(net "GND")
	)
	(via
		(at 396.084298 -149.69236)
		(size 0.508)
		(drill 0.254)
		(layers "F.Cu" "B.Cu")
		(net "GND")
	)
	(via
		(at 178.222148 -350.754188)
		(size 0.508)
		(drill 0.254)
		(layers "F.Cu" "B.Cu")
		(net "GND")
	)
	(via
		(at 105.24871 -246.66956)
		(size 0.4572)
		(drill 0.2032)
		(layers "F.Cu" "B.Cu")
		(net "GND")
	)
	(via
		(at 266.619482 -278.916638)
		(size 0.4572)
		(drill 0.2032)
		(layers "F.Cu" "B.Cu")
		(net "GND")
	)
	(via
		(at 453.121014 -317.166752)
		(size 0.4572)
		(drill 0.2032)
		(layers "F.Cu" "B.Cu")
		(net "GND")
	)
	(via
		(at 149.349968 -430.147222)
		(size 0.4572)
		(drill 0.2032)
		(layers "F.Cu" "B.Cu")
		(net "GND")
	)
	(via
		(at 292.694614 -278.066754)
		(size 0.4572)
		(drill 0.2032)
		(layers "F.Cu" "B.Cu")
		(net "GND")
	)
	(via
		(at 124.437394 -256.361438)
		(size 0.4572)
		(drill 0.2032)
		(layers "F.Cu" "B.Cu")
		(net "GND")
	)
	(via
		(at 142.346934 -17.655032)
		(size 0.508)
		(drill 0.254)
		(layers "F.Cu" "B.Cu")
		(net "GND")
	)
	(via
		(at 459.12532 -15.086838)
		(size 0.508)
		(drill 0.254)
		(layers "F.Cu" "B.Cu")
		(net "GND")
	)
	(via
		(at 56.971946 -403.249892)
		(size 0.4572)
		(drill 0.254)
		(layers "F.Cu" "B.Cu")
		(net "GND")
	)
	(via
		(at 194.193414 -314.616592)
		(size 0.4572)
		(drill 0.2032)
		(layers "F.Cu" "B.Cu")
		(net "GND")
	)
	(via
		(at 122.557794 -280.778204)
		(size 0.4572)
		(drill 0.2032)
		(layers "F.Cu" "B.Cu")
		(net "GND")
	)
	(via
		(at 317.250064 -433.747164)
		(size 0.4572)
		(drill 0.2032)
		(layers "F.Cu" "B.Cu")
		(net "GND")
	)
	(via
		(at 457.221082 -275.516594)
		(size 0.4572)
		(drill 0.2032)
		(layers "F.Cu" "B.Cu")
		(net "GND")
	)
	(via
		(at 19.91741 -398.782032)
		(size 0.508)
		(drill 0.254)
		(layers "F.Cu" "B.Cu")
		(net "GND")
	)
	(via
		(at 371.327934 -213.732618)
		(size 0.4572)
		(drill 0.2032)
		(layers "F.Cu" "B.Cu")
		(net "GND")
	)
	(via
		(at 445.577214 -238.966756)
		(size 0.4572)
		(drill 0.2032)
		(layers "F.Cu" "B.Cu")
		(net "GND")
	)
	(via
		(at 428.279814 -304.416714)
		(size 0.4572)
		(drill 0.2032)
		(layers "F.Cu" "B.Cu")
		(net "GND")
	)
	(via
		(at 104.701848 -287.28924)
		(size 0.4572)
		(drill 0.2032)
		(layers "F.Cu" "B.Cu")
		(net "GND")
	)
	(via
		(at 113.947702 -331.776832)
		(size 0.49022)
		(drill 0.254)
		(layers "F.Cu" "B.Cu")
		(net "GND")
	)
	(via
		(at 276.373082 -221.116652)
		(size 0.4572)
		(drill 0.2032)
		(layers "F.Cu" "B.Cu")
		(net "GND")
	)
	(via
		(at 396.349982 -437.34736)
		(size 0.4572)
		(drill 0.2032)
		(layers "F.Cu" "B.Cu")
		(net "GND")
	)
	(via
		(at 442.133482 -306.96662)
		(size 0.4572)
		(drill 0.2032)
		(layers "F.Cu" "B.Cu")
		(net "GND")
	)
	(via
		(at 410.486352 -323.429376)
		(size 0.4572)
		(drill 0.2032)
		(layers "F.Cu" "B.Cu")
		(net "GND")
	)
	(via
		(at 379.31598 -247.178322)
		(size 0.4572)
		(drill 0.2032)
		(layers "F.Cu" "B.Cu")
		(net "GND")
	)
	(via
		(at 230.984044 -55.16499)
		(size 0.508)
		(drill 0.254)
		(layers "F.Cu" "B.Cu")
		(net "GND")
	)
	(via
		(at 309.992014 -267.016738)
		(size 0.4572)
		(drill 0.2032)
		(layers "F.Cu" "B.Cu")
		(net "GND")
	)
	(via
		(at 127.614172 -351.796858)
		(size 0.508)
		(drill 0.254)
		(layers "F.Cu" "B.Cu")
		(net "GND")
	)
	(via
		(at 129.72796 -84.478368)
		(size 0.508)
		(drill 0.254)
		(layers "F.Cu" "B.Cu")
		(net "GND")
	)
	(via
		(at 274.163282 -289.966654)
		(size 0.4572)
		(drill 0.2032)
		(layers "F.Cu" "B.Cu")
		(net "GND")
	)
	(via
		(at 161.399474 -400.858228)
		(size 0.4064)
		(drill 0.2032)
		(layers "F.Cu" "B.Cu")
		(net "GND")
	)
	(via
		(at 118.300246 -355.914452)
		(size 0.508)
		(drill 0.254)
		(layers "F.Cu" "B.Cu")
		(net "GND")
	)
	(via
		(at 216.824814 -233.86669)
		(size 0.4572)
		(drill 0.2032)
		(layers "F.Cu" "B.Cu")
		(net "GND")
	)
	(via
		(at 359.906316 -332.56601)
		(size 0.49022)
		(drill 0.254)
		(layers "F.Cu" "B.Cu")
		(net "GND")
	)
	(via
		(at 197.637146 -295.06672)
		(size 0.4572)
		(drill 0.2032)
		(layers "F.Cu" "B.Cu")
		(net "GND")
	)
	(via
		(at 29.666946 -287.416748)
		(size 0.4572)
		(drill 0.2032)
		(layers "F.Cu" "B.Cu")
		(net "GND")
	)
	(via
		(at 56.295798 -334.28305)
		(size 0.6604)
		(drill 0.3302)
		(layers "F.Cu" "B.Cu")
		(net "GND")
	)
	(via
		(at 302.448214 -223.666558)
		(size 0.4572)
		(drill 0.2032)
		(layers "F.Cu" "B.Cu")
		(net "GND")
	)
	(via
		(at 103.182166 -226.017328)
		(size 0.4572)
		(drill 0.2032)
		(layers "F.Cu" "B.Cu")
		(net "GND")
	)
	(via
		(at 388.349998 -439.651394)
		(size 0.4572)
		(drill 0.2032)
		(layers "F.Cu" "B.Cu")
		(net "GND")
	)
	(via
		(at 264.729214 -268.71676)
		(size 0.4572)
		(drill 0.2032)
		(layers "F.Cu" "B.Cu")
		(net "GND")
	)
	(via
		(at 335.255362 -271.825212)
		(size 0.4318)
		(drill 0.2032)
		(layers "F.Cu" "B.Cu")
		(net "GND")
	)
	(via
		(at 300.863254 -408.056334)
		(size 0.508)
		(drill 0.254)
		(layers "F.Cu" "B.Cu")
		(net "GND")
	)
	(via
		(at 381.761238 -407.638504)
		(size 0.4572)
		(drill 0.254)
		(layers "F.Cu" "B.Cu")
		(net "GND")
	)
	(via
		(at 186.649614 -224.516696)
		(size 0.4572)
		(drill 0.2032)
		(layers "F.Cu" "B.Cu")
		(net "GND")
	)
	(via
		(at 205.180946 -221.96679)
		(size 0.4572)
		(drill 0.2032)
		(layers "F.Cu" "B.Cu")
		(net "GND")
	)
	(via
		(at 458.455014 -248.31675)
		(size 0.4572)
		(drill 0.2032)
		(layers "F.Cu" "B.Cu")
		(net "GND")
	)
	(via
		(at 20.889214 -267.866622)
		(size 0.4572)
		(drill 0.2032)
		(layers "F.Cu" "B.Cu")
		(net "GND")
	)
	(via
		(at 281.707082 -272.966688)
		(size 0.4572)
		(drill 0.2032)
		(layers "F.Cu" "B.Cu")
		(net "GND")
	)
	(via
		(at 164.66566 -436.893208)
		(size 0.508)
		(drill 0.254)
		(layers "F.Cu" "B.Cu")
		(net "GND")
	)
	(via
		(at 174.04842 -19.545808)
		(size 0.508)
		(drill 0.254)
		(layers "F.Cu" "B.Cu")
		(net "GND")
	)
	(via
		(at 204.0001 -103.762048)
		(size 0.508)
		(drill 0.254)
		(layers "F.Cu" "B.Cu")
		(net "GND")
	)
	(via
		(at 455.011282 -267.866622)
		(size 0.4572)
		(drill 0.2032)
		(layers "F.Cu" "B.Cu")
		(net "GND")
	)
	(via
		(at 29.666946 -301.866808)
		(size 0.4572)
		(drill 0.2032)
		(layers "F.Cu" "B.Cu")
		(net "GND")
	)
	(via
		(at 434.113178 -185.026046)
		(size 0.508)
		(drill 0.254)
		(layers "F.Cu" "B.Cu")
		(net "GND")
	)
	(via
		(at 447.467482 -210.066636)
		(size 0.4572)
		(drill 0.2032)
		(layers "F.Cu" "B.Cu")
		(net "GND")
	)
	(via
		(at 347.958664 -39.149528)
		(size 0.49022)
		(drill 0.254)
		(layers "F.Cu" "B.Cu")
		(net "GND")
	)
	(via
		(at 160.254188 -313.766708)
		(size 0.4572)
		(drill 0.2032)
		(layers "F.Cu" "B.Cu")
		(net "GND")
	)
	(via
		(at 14.579346 -199.01662)
		(size 0.4572)
		(drill 0.2032)
		(layers "F.Cu" "B.Cu")
		(net "GND")
	)
	(via
		(at 43.520614 -244.066568)
		(size 0.4572)
		(drill 0.2032)
		(layers "F.Cu" "B.Cu")
		(net "GND")
	)
	(via
		(at 306.764182 -314.616592)
		(size 0.4572)
		(drill 0.2032)
		(layers "F.Cu" "B.Cu")
		(net "GND")
	)
	(via
		(at 180.339746 -258.516628)
		(size 0.4572)
		(drill 0.2032)
		(layers "F.Cu" "B.Cu")
		(net "GND")
	)
	(via
		(at 110.55096 -408.7368)
		(size 0.508)
		(drill 0.254)
		(layers "F.Cu" "B.Cu")
		(net "GND")
	)
	(via
		(at 347.473016 -271.825212)
		(size 0.4572)
		(drill 0.2032)
		(layers "F.Cu" "B.Cu")
		(net "GND")
	)
	(via
		(at 155.349956 -426.69968)
		(size 0.4572)
		(drill 0.2032)
		(layers "F.Cu" "B.Cu")
		(net "GND")
	)
	(via
		(at 461.108552 -323.353176)
		(size 0.4572)
		(drill 0.2032)
		(layers "F.Cu" "B.Cu")
		(net "GND")
	)
	(via
		(at 438.033414 -221.96679)
		(size 0.4572)
		(drill 0.2032)
		(layers "F.Cu" "B.Cu")
		(net "GND")
	)
	(via
		(at 417.015422 -310.366664)
		(size 0.4572)
		(drill 0.2032)
		(layers "F.Cu" "B.Cu")
		(net "GND")
	)
	(via
		(at 87.315294 -283.219906)
		(size 0.4572)
		(drill 0.2032)
		(layers "F.Cu" "B.Cu")
		(net "GND")
	)
	(via
		(at 406.607772 -18.235422)
		(size 0.508)
		(drill 0.254)
		(layers "F.Cu" "B.Cu")
		(net "GND")
	)
	(via
		(at 415.09569 -410.030168)
		(size 0.4064)
		(drill 0.2032)
		(layers "F.Cu" "B.Cu")
		(net "GND")
	)
	(via
		(at 306.548282 -239.94364)
		(size 0.4572)
		(drill 0.2032)
		(layers "F.Cu" "B.Cu")
		(net "GND")
	)
	(via
		(at 405.445214 -283.166566)
		(size 0.4572)
		(drill 0.2032)
		(layers "F.Cu" "B.Cu")
		(net "GND")
	)
	(via
		(at 107.520994 -280.778204)
		(size 0.4572)
		(drill 0.2032)
		(layers "F.Cu" "B.Cu")
		(net "GND")
	)
	(via
		(at 287.360614 -315.46673)
		(size 0.4572)
		(drill 0.2032)
		(layers "F.Cu" "B.Cu")
		(net "GND")
	)
	(via
		(at 395.37005 -400.858228)
		(size 0.4064)
		(drill 0.2032)
		(layers "F.Cu" "B.Cu")
		(net "GND")
	)
	(via
		(at 178.69408 -31.12516)
		(size 0.508)
		(drill 0.254)
		(layers "F.Cu" "B.Cu")
		(net "GND")
	)
	(via
		(at 216.824814 -224.516696)
		(size 0.4572)
		(drill 0.2032)
		(layers "F.Cu" "B.Cu")
		(net "GND")
	)
	(via
		(at 460.664814 -261.916672)
		(size 0.4572)
		(drill 0.2032)
		(layers "F.Cu" "B.Cu")
		(net "GND")
	)
	(via
		(at 450.911214 -260.21665)
		(size 0.4572)
		(drill 0.2032)
		(layers "F.Cu" "B.Cu")
		(net "GND")
	)
	(via
		(at 443.35319 -30.362906)
		(size 0.508)
		(drill 0.254)
		(layers "F.Cu" "B.Cu")
		(net "GND")
	)
	(via
		(at 458.455014 -273.816572)
		(size 0.4572)
		(drill 0.2032)
		(layers "F.Cu" "B.Cu")
		(net "GND")
	)
	(via
		(at 122.019822 -109.070648)
		(size 0.508)
		(drill 0.254)
		(layers "F.Cu" "B.Cu")
		(net "GND")
	)
	(via
		(at 91.074748 -263.686544)
		(size 0.4572)
		(drill 0.2032)
		(layers "F.Cu" "B.Cu")
		(net "GND")
	)
	(via
		(at 115.482878 -333.356458)
		(size 0.49022)
		(drill 0.254)
		(layers "F.Cu" "B.Cu")
		(net "GND")
	)
	(via
		(at 96.243394 -272.639282)
		(size 0.4572)
		(drill 0.2032)
		(layers "F.Cu" "B.Cu")
		(net "GND")
	)
	(via
		(at 155.27274 -67.633088)
		(size 0.508)
		(drill 0.254)
		(layers "F.Cu" "B.Cu")
		(net "GND")
	)
	(via
		(at 16.789146 -258.516628)
		(size 0.4572)
		(drill 0.2032)
		(layers "F.Cu" "B.Cu")
		(net "GND")
	)
	(via
		(at 119.268494 -276.708616)
		(size 0.4572)
		(drill 0.2032)
		(layers "F.Cu" "B.Cu")
		(net "GND")
	)
	(via
		(at 274.163282 -221.116652)
		(size 0.4572)
		(drill 0.2032)
		(layers "F.Cu" "B.Cu")
		(net "GND")
	)
	(via
		(at 31.876746 -315.46673)
		(size 0.4572)
		(drill 0.2032)
		(layers "F.Cu" "B.Cu")
		(net "GND")
	)
	(via
		(at 258.86283 -127.971042)
		(size 0.508)
		(drill 0.254)
		(layers "F.Cu" "B.Cu")
		(net "GND")
	)
	(via
		(at 212.724746 -229.616762)
		(size 0.4572)
		(drill 0.2032)
		(layers "F.Cu" "B.Cu")
		(net "GND")
	)
	(via
		(at 333.375762 -286.475424)
		(size 0.4572)
		(drill 0.2032)
		(layers "F.Cu" "B.Cu")
		(net "GND")
	)
	(via
		(at 350.652334 -213.732618)
		(size 0.4572)
		(drill 0.2032)
		(layers "F.Cu" "B.Cu")
		(net "GND")
	)
	(via
		(at 369.680744 -339.241892)
		(size 0.508)
		(drill 0.254)
		(layers "F.Cu" "B.Cu")
		(net "GND")
	)
	(via
		(at 380.365762 -286.475424)
		(size 0.4572)
		(drill 0.2032)
		(layers "F.Cu" "B.Cu")
		(net "GND")
	)
	(via
		(at 336.457544 -73.89368)
		(size 0.508)
		(drill 0.254)
		(layers "F.Cu" "B.Cu")
		(net "GND")
	)
	(via
		(at 223.759522 -72.732138)
		(size 0.508)
		(drill 0.254)
		(layers "F.Cu" "B.Cu")
		(net "GND")
	)
	(via
		(at 336.665062 -285.661354)
		(size 0.4572)
		(drill 0.2032)
		(layers "F.Cu" "B.Cu")
		(net "GND")
	)
	(via
		(at 414.070292 -178.016154)
		(size 0.49022)
		(drill 0.254)
		(layers "F.Cu" "B.Cu")
		(net "GND")
	)
	(via
		(at 342.664034 -240.667286)
		(size 0.4572)
		(drill 0.2032)
		(layers "F.Cu" "B.Cu")
		(net "GND")
	)
	(via
		(at 29.666946 -263.616694)
		(size 0.4572)
		(drill 0.2032)
		(layers "F.Cu" "B.Cu")
		(net "GND")
	)
	(via
		(at 342.250014 -436.051198)
		(size 0.4572)
		(drill 0.2032)
		(layers "F.Cu" "B.Cu")
		(net "GND")
	)
	(via
		(at 374.726962 -281.59202)
		(size 0.4572)
		(drill 0.2032)
		(layers "F.Cu" "B.Cu")
		(net "GND")
	)
	(via
		(at 390.116568 -341.973916)
		(size 0.508)
		(drill 0.254)
		(layers "F.Cu" "B.Cu")
		(net "GND")
	)
	(via
		(at 447.467482 -306.96662)
		(size 0.4572)
		(drill 0.2032)
		(layers "F.Cu" "B.Cu")
		(net "GND")
	)
	(via
		(at 240.3094 -421.9194)
		(size 0.508)
		(drill 0.254)
		(layers "F.Cu" "B.Cu")
		(net "GND")
	)
	(via
		(at 184.439814 -286.56661)
		(size 0.4572)
		(drill 0.2032)
		(layers "F.Cu" "B.Cu")
		(net "GND")
	)
	(via
		(at 403.846792 -9.424924)
		(size 0.508)
		(drill 0.254)
		(layers "F.Cu" "B.Cu")
		(net "GND")
	)
	(via
		(at 428.279814 -309.51678)
		(size 0.4572)
		(drill 0.2032)
		(layers "F.Cu" "B.Cu")
		(net "GND")
	)
	(via
		(at 262.519414 -212.616796)
		(size 0.4572)
		(drill 0.2032)
		(layers "F.Cu" "B.Cu")
		(net "GND")
	)
	(via
		(at 332.32598 -222.761556)
		(size 0.4572)
		(drill 0.2032)
		(layers "F.Cu" "B.Cu")
		(net "GND")
	)
	(via
		(at 263.726676 -128.652016)
		(size 0.508)
		(drill 0.254)
		(layers "F.Cu" "B.Cu")
		(net "GND")
	)
	(via
		(at 349.731076 -403.249892)
		(size 0.4572)
		(drill 0.254)
		(layers "F.Cu" "B.Cu")
		(net "GND")
	)
	(via
		(at 375.667016 -260.430772)
		(size 0.4572)
		(drill 0.2032)
		(layers "F.Cu" "B.Cu")
		(net "GND")
	)
	(via
		(at 426.213524 -6.586474)
		(size 0.508)
		(drill 0.254)
		(layers "F.Cu" "B.Cu")
		(net "GND")
	)
	(via
		(at 107.881166 -219.506038)
		(size 0.4572)
		(drill 0.2032)
		(layers "F.Cu" "B.Cu")
		(net "GND")
	)
	(via
		(at 435.823614 -265.316716)
		(size 0.4572)
		(drill 0.2032)
		(layers "F.Cu" "B.Cu")
		(net "GND")
	)
	(via
		(at 428.279814 -279.766776)
		(size 0.4572)
		(drill 0.2032)
		(layers "F.Cu" "B.Cu")
		(net "GND")
	)
	(via
		(at 66.152014 -196.466714)
		(size 0.4572)
		(drill 0.2032)
		(layers "F.Cu" "B.Cu")
		(net "GND")
	)
	(via
		(at 197.637146 -229.616762)
		(size 0.4572)
		(drill 0.2032)
		(layers "F.Cu" "B.Cu")
		(net "GND")
	)
	(via
		(at 110.230666 -226.831144)
		(size 0.4572)
		(drill 0.2032)
		(layers "F.Cu" "B.Cu")
		(net "GND")
	)
	(via
		(at 306.548282 -282.316682)
		(size 0.4572)
		(drill 0.2032)
		(layers "F.Cu" "B.Cu")
		(net "GND")
	)
	(via
		(at 341.105998 -47.980346)
		(size 0.4572)
		(drill 0.2032)
		(layers "F.Cu" "B.Cu")
		(net "GND")
	)
	(via
		(at 22.123146 -214.316564)
		(size 0.4572)
		(drill 0.2032)
		(layers "F.Cu" "B.Cu")
		(net "GND")
	)
	(via
		(at 364.279434 -226.017328)
		(size 0.4572)
		(drill 0.2032)
		(layers "F.Cu" "B.Cu")
		(net "GND")
	)
	(via
		(at 47.811182 -350.984058)
		(size 0.508)
		(drill 0.254)
		(layers "F.Cu" "B.Cu")
		(net "GND")
	)
	(via
		(at 207.071214 -250.866656)
		(size 0.4572)
		(drill 0.2032)
		(layers "F.Cu" "B.Cu")
		(net "GND")
	)
	(via
		(at 49.240694 -351.608644)
		(size 0.49022)
		(drill 0.254)
		(layers "F.Cu" "B.Cu")
		(net "GND")
	)
	(via
		(at 39.743126 -183.30164)
		(size 0.508)
		(drill 0.254)
		(layers "F.Cu" "B.Cu")
		(net "GND")
	)
	(via
		(at 464.764882 -207.51673)
		(size 0.4572)
		(drill 0.2032)
		(layers "F.Cu" "B.Cu")
		(net "GND")
	)
	(via
		(at 191.983614 -202.416664)
		(size 0.4572)
		(drill 0.2032)
		(layers "F.Cu" "B.Cu")
		(net "GND")
	)
	(via
		(at 335.725262 -271.011396)
		(size 0.4572)
		(drill 0.2032)
		(layers "F.Cu" "B.Cu")
		(net "GND")
	)
	(via
		(at 216.824814 -272.966688)
		(size 0.4572)
		(drill 0.2032)
		(layers "F.Cu" "B.Cu")
		(net "GND")
	)
	(via
		(at 58.608214 -230.466646)
		(size 0.4572)
		(drill 0.2032)
		(layers "F.Cu" "B.Cu")
		(net "GND")
	)
	(via
		(at 367.678462 -267.755878)
		(size 0.4572)
		(drill 0.2032)
		(layers "F.Cu" "B.Cu")
		(net "GND")
	)
	(via
		(at 375.56694 -335.187036)
		(size 0.49022)
		(drill 0.254)
		(layers "F.Cu" "B.Cu")
		(net "GND")
	)
	(via
		(at 216.824814 -312.91657)
		(size 0.4572)
		(drill 0.2032)
		(layers "F.Cu" "B.Cu")
		(net "GND")
	)
	(via
		(at 100.824284 -396.44574)
		(size 0.508)
		(drill 0.254)
		(layers "F.Cu" "B.Cu")
		(net "GND")
	)
	(via
		(at 21.5138 -413.258)
		(size 0.508)
		(drill 0.254)
		(layers "F.Cu" "B.Cu")
		(net "GND")
	)
	(via
		(at 384.485134 -231.714548)
		(size 0.4318)
		(drill 0.2032)
		(layers "F.Cu" "B.Cu")
		(net "GND")
	)
	(via
		(at 239.175036 -49.136554)
		(size 0.508)
		(drill 0.254)
		(layers "F.Cu" "B.Cu")
		(net "GND")
	)
	(via
		(at 216.824814 -200.716642)
		(size 0.4572)
		(drill 0.2032)
		(layers "F.Cu" "B.Cu")
		(net "GND")
	)
	(via
		(at 169.696384 -345.648788)
		(size 0.508)
		(drill 0.254)
		(layers "F.Cu" "B.Cu")
		(net "GND")
	)
	(via
		(at 326.48398 -404.51786)
		(size 0.4572)
		(drill 0.254)
		(layers "F.Cu" "B.Cu")
		(net "GND")
	)
	(via
		(at 88.950546 -410.664152)
		(size 0.4572)
		(drill 0.254)
		(layers "F.Cu" "B.Cu")
		(net "GND")
	)
	(via
		(at 413.192214 -221.96679)
		(size 0.4572)
		(drill 0.2032)
		(layers "F.Cu" "B.Cu")
		(net "GND")
	)
	(via
		(at 371.225318 -404.51786)
		(size 0.4572)
		(drill 0.254)
		(layers "F.Cu" "B.Cu")
		(net "GND")
	)
	(via
		(at 419.502082 -194.766692)
		(size 0.4572)
		(drill 0.2032)
		(layers "F.Cu" "B.Cu")
		(net "GND")
	)
	(via
		(at 199.527414 -196.466714)
		(size 0.4572)
		(drill 0.2032)
		(layers "F.Cu" "B.Cu")
		(net "GND")
	)
	(via
		(at 270.97228 -38.514528)
		(size 0.508)
		(drill 0.254)
		(layers "F.Cu" "B.Cu")
		(net "GND")
	)
	(via
		(at 403.349968 -427.851316)
		(size 0.4572)
		(drill 0.2032)
		(layers "F.Cu" "B.Cu")
		(net "GND")
	)
	(via
		(at 302.448214 -261.916672)
		(size 0.4572)
		(drill 0.2032)
		(layers "F.Cu" "B.Cu")
		(net "GND")
	)
	(via
		(at 390.950958 -406.34666)
		(size 0.4572)
		(drill 0.254)
		(layers "F.Cu" "B.Cu")
		(net "GND")
	)
	(via
		(at 434.589682 -289.966654)
		(size 0.4572)
		(drill 0.2032)
		(layers "F.Cu" "B.Cu")
		(net "GND")
	)
	(via
		(at 354.991416 -278.336502)
		(size 0.4572)
		(drill 0.2032)
		(layers "F.Cu" "B.Cu")
		(net "GND")
	)
	(via
		(at 327.137522 -59.371992)
		(size 0.508)
		(drill 0.254)
		(layers "F.Cu" "B.Cu")
		(net "GND")
	)
	(via
		(at 21.405596 -385.475226)
		(size 0.508)
		(drill 0.254)
		(layers "F.Cu" "B.Cu")
		(net "GND")
	)
	(via
		(at 155.61818 -36.289488)
		(size 0.508)
		(drill 0.254)
		(layers "F.Cu" "B.Cu")
		(net "GND")
	)
	(via
		(at 372.377716 -254.733552)
		(size 0.4572)
		(drill 0.2032)
		(layers "F.Cu" "B.Cu")
		(net "GND")
	)
	(via
		(at 360.240072 -43.610784)
		(size 0.508)
		(drill 0.254)
		(layers "F.Cu" "B.Cu")
		(net "GND")
	)
	(via
		(at 447.467482 -295.916604)
		(size 0.4572)
		(drill 0.2032)
		(layers "F.Cu" "B.Cu")
		(net "GND")
	)
	(via
		(at 124.327412 -244.73662)
		(size 0.4572)
		(drill 0.2032)
		(layers "F.Cu" "B.Cu")
		(net "GND")
	)
	(via
		(at 291.460682 -232.166668)
		(size 0.4572)
		(drill 0.2032)
		(layers "F.Cu" "B.Cu")
		(net "GND")
	)
	(via
		(at 346.533216 -281.59202)
		(size 0.4572)
		(drill 0.2032)
		(layers "F.Cu" "B.Cu")
		(net "GND")
	)
	(via
		(at 407.858214 -261.916672)
		(size 0.4572)
		(drill 0.2032)
		(layers "F.Cu" "B.Cu")
		(net "GND")
	)
	(via
		(at 350.9899 -403.249892)
		(size 0.4572)
		(drill 0.254)
		(layers "F.Cu" "B.Cu")
		(net "GND")
	)
	(via
		(at 314.092082 -299.316648)
		(size 0.4572)
		(drill 0.2032)
		(layers "F.Cu" "B.Cu")
		(net "GND")
	)
	(via
		(at 462.555082 -280.61666)
		(size 0.4572)
		(drill 0.2032)
		(layers "F.Cu" "B.Cu")
		(net "GND")
	)
	(via
		(at 268.829282 -211.766658)
		(size 0.4572)
		(drill 0.2032)
		(layers "F.Cu" "B.Cu")
		(net "GND")
	)
	(via
		(at 172.8724 -95.367348)
		(size 0.508)
		(drill 0.254)
		(layers "F.Cu" "B.Cu")
		(net "GND")
	)
	(via
		(at 346.250006 -427.699678)
		(size 0.4572)
		(drill 0.2032)
		(layers "F.Cu" "B.Cu")
		(net "GND")
	)
	(via
		(at 157.708346 -287.416748)
		(size 0.4572)
		(drill 0.2032)
		(layers "F.Cu" "B.Cu")
		(net "GND")
	)
	(via
		(at 187.397136 -345.444318)
		(size 0.508)
		(drill 0.254)
		(layers "F.Cu" "B.Cu")
		(net "GND")
	)
	(via
		(at 430.489614 -220.266768)
		(size 0.4572)
		(drill 0.2032)
		(layers "F.Cu" "B.Cu")
		(net "GND")
	)
	(via
		(at 435.823614 -214.316564)
		(size 0.4572)
		(drill 0.2032)
		(layers "F.Cu" "B.Cu")
		(net "GND")
	)
	(via
		(at 327.96607 -341.063072)
		(size 0.49022)
		(drill 0.254)
		(layers "F.Cu" "B.Cu")
		(net "GND")
	)
	(via
		(at 44.754546 -300.166786)
		(size 0.4572)
		(drill 0.2032)
		(layers "F.Cu" "B.Cu")
		(net "GND")
	)
	(via
		(at 90.494612 -225.203258)
		(size 0.4572)
		(drill 0.2032)
		(layers "F.Cu" "B.Cu")
		(net "GND")
	)
	(via
		(at 337.49488 -234.970066)
		(size 0.4572)
		(drill 0.2032)
		(layers "F.Cu" "B.Cu")
		(net "GND")
	)
	(via
		(at 29.666946 -306.116736)
		(size 0.4572)
		(drill 0.2032)
		(layers "F.Cu" "B.Cu")
		(net "GND")
	)
	(via
		(at 372.847362 -255.547622)
		(size 0.4572)
		(drill 0.2032)
		(layers "F.Cu" "B.Cu")
		(net "GND")
	)
	(via
		(at 438.277 -97.450148)
		(size 0.508)
		(drill 0.254)
		(layers "F.Cu" "B.Cu")
		(net "GND")
	)
	(via
		(at 321.250056 -437.34736)
		(size 0.4572)
		(drill 0.2032)
		(layers "F.Cu" "B.Cu")
		(net "GND")
	)
	(via
		(at 270.063214 -238.966756)
		(size 0.4572)
		(drill 0.2032)
		(layers "F.Cu" "B.Cu")
		(net "GND")
	)
	(via
		(at 96.133412 -246.364506)
		(size 0.4572)
		(drill 0.2032)
		(layers "F.Cu" "B.Cu")
		(net "GND")
	)
	(via
		(at 98.122994 -261.244842)
		(size 0.4572)
		(drill 0.2032)
		(layers "F.Cu" "B.Cu")
		(net "GND")
	)
	(via
		(at 164.280596 -207.51673)
		(size 0.4572)
		(drill 0.2032)
		(layers "F.Cu" "B.Cu")
		(net "GND")
	)
	(via
		(at 56.045608 -150.03145)
		(size 0.49022)
		(drill 0.254)
		(layers "F.Cu" "B.Cu")
		(net "GND")
	)
	(via
		(at 191.983614 -247.466612)
		(size 0.4572)
		(drill 0.2032)
		(layers "F.Cu" "B.Cu")
		(net "GND")
	)
	(via
		(at 164.3888 -89.9922)
		(size 0.508)
		(drill 0.254)
		(layers "F.Cu" "B.Cu")
		(net "GND")
	)
	(via
		(at 453.121014 -210.916774)
		(size 0.4572)
		(drill 0.2032)
		(layers "F.Cu" "B.Cu")
		(net "GND")
	)
	(via
		(at 370.85778 -234.15625)
		(size 0.4572)
		(drill 0.2032)
		(layers "F.Cu" "B.Cu")
		(net "GND")
	)
	(via
		(at 361.569762 -266.941808)
		(size 0.4572)
		(drill 0.2032)
		(layers "F.Cu" "B.Cu")
		(net "GND")
	)
	(via
		(at 101.412548 -262.058658)
		(size 0.4572)
		(drill 0.2032)
		(layers "F.Cu" "B.Cu")
		(net "GND")
	)
	(via
		(at 187.883546 -227.066602)
		(size 0.4572)
		(drill 0.2032)
		(layers "F.Cu" "B.Cu")
		(net "GND")
	)
	(via
		(at 128.086612 -244.73662)
		(size 0.4572)
		(drill 0.2032)
		(layers "F.Cu" "B.Cu")
		(net "GND")
	)
	(via
		(at 409.748482 -261.066788)
		(size 0.4572)
		(drill 0.2032)
		(layers "F.Cu" "B.Cu")
		(net "GND")
	)
	(via
		(at 405.648414 -248.31675)
		(size 0.4572)
		(drill 0.2032)
		(layers "F.Cu" "B.Cu")
		(net "GND")
	)
	(via
		(at 182.549546 -234.716574)
		(size 0.4572)
		(drill 0.2032)
		(layers "F.Cu" "B.Cu")
		(net "GND")
	)
	(via
		(at 14.579346 -236.416596)
		(size 0.4572)
		(drill 0.2032)
		(layers "F.Cu" "B.Cu")
		(net "GND")
	)
	(via
		(at 27.277822 -6.090412)
		(size 0.508)
		(drill 0.254)
		(layers "F.Cu" "B.Cu")
		(net "GND")
	)
	(via
		(at 356.291134 -223.575626)
		(size 0.4572)
		(drill 0.2032)
		(layers "F.Cu" "B.Cu")
		(net "GND")
	)
	(via
		(at 16.2941 -110.482888)
		(size 0.508)
		(drill 0.254)
		(layers "F.Cu" "B.Cu")
		(net "GND")
	)
	(via
		(at 187.883546 -225.36658)
		(size 0.4572)
		(drill 0.2032)
		(layers "F.Cu" "B.Cu")
		(net "GND")
	)
	(via
		(at 378.84608 -244.73662)
		(size 0.4572)
		(drill 0.2032)
		(layers "F.Cu" "B.Cu")
		(net "GND")
	)
	(via
		(at 257.100832 -439.905394)
		(size 0.508)
		(drill 0.254)
		(layers "F.Cu" "B.Cu")
		(net "GND")
	)
	(via
		(at 176.853088 -356.75824)
		(size 0.508)
		(drill 0.254)
		(layers "F.Cu" "B.Cu")
		(net "GND")
	)
	(via
		(at 148.511514 -407.00452)
		(size 0.4064)
		(drill 0.2032)
		(layers "F.Cu" "B.Cu")
		(net "GND")
	)
	(via
		(at 78.250034 -439.651394)
		(size 0.4572)
		(drill 0.2032)
		(layers "F.Cu" "B.Cu")
		(net "GND")
	)
	(via
		(at 207.071214 -286.56661)
		(size 0.4572)
		(drill 0.2032)
		(layers "F.Cu" "B.Cu")
		(net "GND")
	)
	(via
		(at 302.448214 -231.316784)
		(size 0.4572)
		(drill 0.2032)
		(layers "F.Cu" "B.Cu")
		(net "GND")
	)
	(via
		(at 262.519414 -272.116804)
		(size 0.4572)
		(drill 0.2032)
		(layers "F.Cu" "B.Cu")
		(net "GND")
	)
	(via
		(at 88.724994 -279.150318)
		(size 0.4572)
		(drill 0.2032)
		(layers "F.Cu" "B.Cu")
		(net "GND")
	)
	(via
		(at 89.554812 -246.364506)
		(size 0.4572)
		(drill 0.2032)
		(layers "F.Cu" "B.Cu")
		(net "GND")
	)
	(via
		(at 117.964458 -330.90612)
		(size 0.508)
		(drill 0.254)
		(layers "F.Cu" "B.Cu")
		(net "GND")
	)
	(via
		(at 7.035546 -309.51678)
		(size 0.4572)
		(drill 0.2032)
		(layers "F.Cu" "B.Cu")
		(net "GND")
	)
	(via
		(at 126.883414 -365.429292)
		(size 0.508)
		(drill 0.254)
		(layers "F.Cu" "B.Cu")
		(net "GND")
	)
	(via
		(at 266.619482 -301.01667)
		(size 0.4572)
		(drill 0.2032)
		(layers "F.Cu" "B.Cu")
		(net "GND")
	)
	(via
		(at 257.185414 -272.116804)
		(size 0.4572)
		(drill 0.2032)
		(layers "F.Cu" "B.Cu")
		(net "GND")
	)
	(via
		(at 460.664814 -301.866808)
		(size 0.4572)
		(drill 0.2032)
		(layers "F.Cu" "B.Cu")
		(net "GND")
	)
	(via
		(at 306.3875 -406.370536)
		(size 0.4572)
		(drill 0.254)
		(layers "F.Cu" "B.Cu")
		(net "GND")
	)
	(via
		(at 14.579346 -268.71676)
		(size 0.4572)
		(drill 0.2032)
		(layers "F.Cu" "B.Cu")
		(net "GND")
	)
	(via
		(at 382.135634 -242.294918)
		(size 0.4572)
		(drill 0.2032)
		(layers "F.Cu" "B.Cu")
		(net "GND")
	)
	(via
		(at 182.549546 -258.516628)
		(size 0.4572)
		(drill 0.2032)
		(layers "F.Cu" "B.Cu")
		(net "GND")
	)
	(via
		(at 336.53603 -342.106758)
		(size 0.508)
		(drill 0.254)
		(layers "F.Cu" "B.Cu")
		(net "GND")
	)
	(via
		(at 175.005746 -233.016806)
		(size 0.4572)
		(drill 0.2032)
		(layers "F.Cu" "B.Cu")
		(net "GND")
	)
	(via
		(at 458.455014 -197.316598)
		(size 0.4572)
		(drill 0.2032)
		(layers "F.Cu" "B.Cu")
		(net "GND")
	)
	(via
		(at 382.245616 -276.708616)
		(size 0.4572)
		(drill 0.2032)
		(layers "F.Cu" "B.Cu")
		(net "GND")
	)
	(via
		(at 327.250044 -438.651396)
		(size 0.4572)
		(drill 0.2032)
		(layers "F.Cu" "B.Cu")
		(net "GND")
	)
	(via
		(at 419.502082 -271.266666)
		(size 0.4572)
		(drill 0.2032)
		(layers "F.Cu" "B.Cu")
		(net "GND")
	)
	(via
		(at 370.497862 -274.266914)
		(size 0.4572)
		(drill 0.2032)
		(layers "F.Cu" "B.Cu")
		(net "GND")
	)
	(via
		(at 375.087134 -217.064336)
		(size 0.4572)
		(drill 0.2032)
		(layers "F.Cu" "B.Cu")
		(net "GND")
	)
	(via
		(at 364.702598 -292.955726)
		(size 0.508)
		(drill 0.254)
		(layers "F.Cu" "B.Cu")
		(net "GND")
	)
	(via
		(at 147.349972 -437.49976)
		(size 0.4572)
		(drill 0.2032)
		(layers "F.Cu" "B.Cu")
		(net "GND")
	)
	(via
		(at 134.305548 -273.453098)
		(size 0.4572)
		(drill 0.2032)
		(layers "F.Cu" "B.Cu")
		(net "GND")
	)
	(via
		(at 325.250048 -433.747164)
		(size 0.4572)
		(drill 0.2032)
		(layers "F.Cu" "B.Cu")
		(net "GND")
	)
	(via
		(at 195.427346 -276.366732)
		(size 0.4572)
		(drill 0.2032)
		(layers "F.Cu" "B.Cu")
		(net "GND")
	)
	(via
		(at 59.842146 -227.066602)
		(size 0.4572)
		(drill 0.2032)
		(layers "F.Cu" "B.Cu")
		(net "GND")
	)
	(via
		(at 128.666748 -255.547622)
		(size 0.4572)
		(drill 0.2032)
		(layers "F.Cu" "B.Cu")
		(net "GND")
	)
	(via
		(at 338.90458 -240.667286)
		(size 0.4572)
		(drill 0.2032)
		(layers "F.Cu" "B.Cu")
		(net "GND")
	)
	(via
		(at 164.018214 -271.266666)
		(size 0.4572)
		(drill 0.2032)
		(layers "F.Cu" "B.Cu")
		(net "GND")
	)
	(via
		(at 159.418274 -403.883876)
		(size 0.4064)
		(drill 0.2032)
		(layers "F.Cu" "B.Cu")
		(net "GND")
	)
	(via
		(at 207.071214 -271.266666)
		(size 0.4572)
		(drill 0.2032)
		(layers "F.Cu" "B.Cu")
		(net "GND")
	)
	(via
		(at 59.250072 -432.747166)
		(size 0.4572)
		(drill 0.2032)
		(layers "F.Cu" "B.Cu")
		(net "GND")
	)
	(via
		(at 117.749066 -226.831144)
		(size 0.4572)
		(drill 0.2032)
		(layers "F.Cu" "B.Cu")
		(net "GND")
	)
	(via
		(at 44.754546 -261.916672)
		(size 0.4572)
		(drill 0.2032)
		(layers "F.Cu" "B.Cu")
		(net "GND")
	)
	(via
		(at 375.836434 -358.244394)
		(size 0.508)
		(drill 0.254)
		(layers "F.Cu" "B.Cu")
		(net "GND")
	)
	(via
		(at 90.604848 -277.522432)
		(size 0.4572)
		(drill 0.2032)
		(layers "F.Cu" "B.Cu")
		(net "GND")
	)
	(via
		(at 51.064414 -232.166668)
		(size 0.4572)
		(drill 0.2032)
		(layers "F.Cu" "B.Cu")
		(net "GND")
	)
	(via
		(at 214.615014 -305.266598)
		(size 0.4572)
		(drill 0.2032)
		(layers "F.Cu" "B.Cu")
		(net "GND")
	)
	(via
		(at 356.54996 -392.04265)
		(size 0.508)
		(drill 0.254)
		(layers "F.Cu" "B.Cu")
		(net "GND")
	)
	(via
		(at 150.589742 -404.51786)
		(size 0.4572)
		(drill 0.254)
		(layers "F.Cu" "B.Cu")
		(net "GND")
	)
	(via
		(at 88.615012 -234.970066)
		(size 0.4572)
		(drill 0.2032)
		(layers "F.Cu" "B.Cu")
		(net "GND")
	)
	(via
		(at 36.792916 -432.406806)
		(size 0.508)
		(drill 0.254)
		(layers "F.Cu" "B.Cu")
		(net "GND")
	)
	(via
		(at 157.708346 -201.56678)
		(size 0.4572)
		(drill 0.2032)
		(layers "F.Cu" "B.Cu")
		(net "GND")
	)
	(via
		(at 79.8068 -148.661628)
		(size 0.508)
		(drill 0.254)
		(layers "F.Cu" "B.Cu")
		(net "GND")
	)
	(via
		(at 281.707082 -312.91657)
		(size 0.4572)
		(drill 0.2032)
		(layers "F.Cu" "B.Cu")
		(net "GND")
	)
	(via
		(at 111.764826 -400.509486)
		(size 0.508)
		(drill 0.254)
		(layers "F.Cu" "B.Cu")
		(net "GND")
	)
	(via
		(at 432.379882 -297.616626)
		(size 0.4572)
		(drill 0.2032)
		(layers "F.Cu" "B.Cu")
		(net "GND")
	)
	(via
		(at 262.519414 -223.666558)
		(size 0.4572)
		(drill 0.2032)
		(layers "F.Cu" "B.Cu")
		(net "GND")
	)
	(via
		(at 336.085434 -239.0394)
		(size 0.4572)
		(drill 0.2032)
		(layers "F.Cu" "B.Cu")
		(net "GND")
	)
	(via
		(at 421.859964 -138.874246)
		(size 0.508)
		(drill 0.254)
		(layers "F.Cu" "B.Cu")
		(net "GND")
	)
	(via
		(at 328.625708 -47.510446)
		(size 0.4572)
		(drill 0.2032)
		(layers "F.Cu" "B.Cu")
		(net "GND")
	)
	(via
		(at 31.876746 -229.616762)
		(size 0.4572)
		(drill 0.2032)
		(layers "F.Cu" "B.Cu")
		(net "GND")
	)
	(via
		(at 14.579346 -281.466798)
		(size 0.4572)
		(drill 0.2032)
		(layers "F.Cu" "B.Cu")
		(net "GND")
	)
	(via
		(at 360.382312 -335.704434)
		(size 0.49022)
		(drill 0.254)
		(layers "F.Cu" "B.Cu")
		(net "GND")
	)
	(via
		(at 54.021736 -436.957978)
		(size 0.508)
		(drill 0.254)
		(layers "F.Cu" "B.Cu")
		(net "GND")
	)
	(via
		(at 279.816814 -231.316784)
		(size 0.4572)
		(drill 0.2032)
		(layers "F.Cu" "B.Cu")
		(net "GND")
	)
	(via
		(at 272.273014 -220.266768)
		(size 0.4572)
		(drill 0.2032)
		(layers "F.Cu" "B.Cu")
		(net "GND")
	)
	(via
		(at 289.250882 -277.216616)
		(size 0.4572)
		(drill 0.2032)
		(layers "F.Cu" "B.Cu")
		(net "GND")
	)
	(via
		(at 409.748482 -314.616592)
		(size 0.4572)
		(drill 0.2032)
		(layers "F.Cu" "B.Cu")
		(net "GND")
	)
	(via
		(at 84.541106 -401.492212)
		(size 0.4572)
		(drill 0.254)
		(layers "F.Cu" "B.Cu")
		(net "GND")
	)
	(via
		(at 330.396596 -39.443152)
		(size 0.4572)
		(drill 0.2032)
		(layers "F.Cu" "B.Cu")
		(net "GND")
	)
	(via
		(at 165.252146 -221.96679)
		(size 0.4572)
		(drill 0.2032)
		(layers "F.Cu" "B.Cu")
		(net "GND")
	)
	(via
		(at 209.281014 -194.766692)
		(size 0.4572)
		(drill 0.2032)
		(layers "F.Cu" "B.Cu")
		(net "GND")
	)
	(via
		(at 357.586026 -326.948292)
		(size 0.508)
		(drill 0.254)
		(layers "F.Cu" "B.Cu")
		(net "GND")
	)
	(via
		(at 390.349994 -435.0512)
		(size 0.4572)
		(drill 0.2032)
		(layers "F.Cu" "B.Cu")
		(net "GND")
	)
	(via
		(at 41.310814 -264.466578)
		(size 0.4572)
		(drill 0.2032)
		(layers "F.Cu" "B.Cu")
		(net "GND")
	)
	(via
		(at 56.364124 -177.987452)
		(size 0.508)
		(drill 0.254)
		(layers "F.Cu" "B.Cu")
		(net "GND")
	)
	(via
		(at 141.367002 -339.831172)
		(size 0.508)
		(drill 0.254)
		(layers "F.Cu" "B.Cu")
		(net "GND")
	)
	(via
		(at 85.40496 -38.287452)
		(size 0.508)
		(drill 0.254)
		(layers "F.Cu" "B.Cu")
		(net "GND")
	)
	(via
		(at 344.245692 -332.56601)
		(size 0.49022)
		(drill 0.254)
		(layers "F.Cu" "B.Cu")
		(net "GND")
	)
	(via
		(at 176.155604 -114.975386)
		(size 0.4572)
		(drill 0.254)
		(layers "F.Cu" "B.Cu")
		(net "GND")
	)
	(via
		(at 372.26748 -231.714548)
		(size 0.4572)
		(drill 0.2032)
		(layers "F.Cu" "B.Cu")
		(net "GND")
	)
	(via
		(at 133.176518 -360.76509)
		(size 0.6604)
		(drill 0.3302)
		(layers "F.Cu" "B.Cu")
		(net "GND")
	)
	(via
		(at 87.785194 -254.733552)
		(size 0.4572)
		(drill 0.2032)
		(layers "F.Cu" "B.Cu")
		(net "GND")
	)
	(via
		(at 435.823614 -236.416596)
		(size 0.4572)
		(drill 0.2032)
		(layers "F.Cu" "B.Cu")
		(net "GND")
	)
	(via
		(at 328.400664 -344.965274)
		(size 0.49022)
		(drill 0.254)
		(layers "F.Cu" "B.Cu")
		(net "GND")
	)
	(via
		(at 172.795946 -272.116804)
		(size 0.4572)
		(drill 0.2032)
		(layers "F.Cu" "B.Cu")
		(net "GND")
	)
	(via
		(at 168.510966 -407.638504)
		(size 0.4572)
		(drill 0.254)
		(layers "F.Cu" "B.Cu")
		(net "GND")
	)
	(via
		(at 254.45974 -422.9608)
		(size 0.508)
		(drill 0.254)
		(layers "F.Cu" "B.Cu")
		(net "GND")
	)
	(via
		(at 89.224358 -403.883876)
		(size 0.4064)
		(drill 0.2032)
		(layers "F.Cu" "B.Cu")
		(net "GND")
	)
	(via
		(at 24.332946 -195.616576)
		(size 0.4572)
		(drill 0.2032)
		(layers "F.Cu" "B.Cu")
		(net "GND")
	)
	(via
		(at 130.436366 -219.506038)
		(size 0.4572)
		(drill 0.2032)
		(layers "F.Cu" "B.Cu")
		(net "GND")
	)
	(via
		(at 250.763786 -70.127876)
		(size 0.508)
		(drill 0.254)
		(layers "F.Cu" "B.Cu")
		(net "GND")
	)
	(via
		(at 136.184894 -260.430772)
		(size 0.4318)
		(drill 0.2032)
		(layers "F.Cu" "B.Cu")
		(net "GND")
	)
	(via
		(at 342.773762 -283.219906)
		(size 0.4572)
		(drill 0.2032)
		(layers "F.Cu" "B.Cu")
		(net "GND")
	)
	(via
		(at 116.852446 -326.892412)
		(size 0.508)
		(drill 0.254)
		(layers "F.Cu" "B.Cu")
		(net "GND")
	)
	(via
		(at 361.569762 -260.430772)
		(size 0.4572)
		(drill 0.2032)
		(layers "F.Cu" "B.Cu")
		(net "GND")
	)
	(via
		(at 335.145126 -216.25052)
		(size 0.4572)
		(drill 0.2032)
		(layers "F.Cu" "B.Cu")
		(net "GND")
	)
	(via
		(at 116.339366 -219.506038)
		(size 0.4572)
		(drill 0.2032)
		(layers "F.Cu" "B.Cu")
		(net "GND")
	)
	(via
		(at 400.24685 -7.215124)
		(size 0.508)
		(drill 0.254)
		(layers "F.Cu" "B.Cu")
		(net "GND")
	)
	(via
		(at 291.460682 -264.466578)
		(size 0.4572)
		(drill 0.2032)
		(layers "F.Cu" "B.Cu")
		(net "GND")
	)
	(via
		(at 57.586118 -19.770344)
		(size 0.508)
		(drill 0.254)
		(layers "F.Cu" "B.Cu")
		(net "GND")
	)
	(via
		(at 277.607014 -260.21665)
		(size 0.4572)
		(drill 0.2032)
		(layers "F.Cu" "B.Cu")
		(net "GND")
	)
	(via
		(at 60.551822 -162.17646)
		(size 0.508)
		(drill 0.254)
		(layers "F.Cu" "B.Cu")
		(net "GND")
	)
	(via
		(at 356.51186 -389.19277)
		(size 0.508)
		(drill 0.254)
		(layers "F.Cu" "B.Cu")
		(net "GND")
	)
	(via
		(at 0.76454 -61.800232)
		(size 0.508)
		(drill 0.254)
		(layers "F.Cu" "B.Cu")
		(net "GND")
	)
	(via
		(at 184.439814 -207.51673)
		(size 0.4572)
		(drill 0.2032)
		(layers "F.Cu" "B.Cu")
		(net "GND")
	)
	(via
		(at 76.112878 -23.495762)
		(size 0.508)
		(drill 0.254)
		(layers "F.Cu" "B.Cu")
		(net "GND")
	)
	(via
		(at 345.953334 -228.45903)
		(size 0.4572)
		(drill 0.2032)
		(layers "F.Cu" "B.Cu")
		(net "GND")
	)
	(via
		(at 261.285482 -224.516696)
		(size 0.4572)
		(drill 0.2032)
		(layers "F.Cu" "B.Cu")
		(net "GND")
	)
	(via
		(at 207.071214 -207.51673)
		(size 0.4572)
		(drill 0.2032)
		(layers "F.Cu" "B.Cu")
		(net "GND")
	)
	(via
		(at 307.782214 -309.51678)
		(size 0.4572)
		(drill 0.2032)
		(layers "F.Cu" "B.Cu")
		(net "GND")
	)
	(via
		(at 159.418274 -400.858228)
		(size 0.4064)
		(drill 0.2032)
		(layers "F.Cu" "B.Cu")
		(net "GND")
	)
	(via
		(at 272.273014 -225.36658)
		(size 0.4572)
		(drill 0.2032)
		(layers "F.Cu" "B.Cu")
		(net "GND")
	)
	(via
		(at 33.767014 -301.01667)
		(size 0.4572)
		(drill 0.2032)
		(layers "F.Cu" "B.Cu")
		(net "GND")
	)
	(via
		(at 91.42222 -186.17819)
		(size 0.508)
		(drill 0.254)
		(layers "F.Cu" "B.Cu")
		(net "GND")
	)
	(via
		(at 66.152014 -205.816708)
		(size 0.4572)
		(drill 0.2032)
		(layers "F.Cu" "B.Cu")
		(net "GND")
	)
	(via
		(at 305.0413 -403.249892)
		(size 0.4572)
		(drill 0.254)
		(layers "F.Cu" "B.Cu")
		(net "GND")
	)
	(via
		(at 374.4214 -186.858148)
		(size 0.508)
		(drill 0.254)
		(layers "F.Cu" "B.Cu")
		(net "GND")
	)
	(via
		(at 194.193414 -277.216616)
		(size 0.4572)
		(drill 0.2032)
		(layers "F.Cu" "B.Cu")
		(net "GND")
	)
	(via
		(at 421.618156 -165.018974)
		(size 0.508)
		(drill 0.254)
		(layers "F.Cu" "B.Cu")
		(net "GND")
	)
	(via
		(at 336.195162 -253.919736)
		(size 0.4572)
		(drill 0.2032)
		(layers "F.Cu" "B.Cu")
		(net "GND")
	)
	(via
		(at 287.360614 -304.416714)
		(size 0.4572)
		(drill 0.2032)
		(layers "F.Cu" "B.Cu")
		(net "GND")
	)
	(via
		(at 48.2092 -179.085748)
		(size 0.508)
		(drill 0.254)
		(layers "F.Cu" "B.Cu")
		(net "GND")
	)
	(via
		(at 63.942214 -275.516594)
		(size 0.4572)
		(drill 0.2032)
		(layers "F.Cu" "B.Cu")
		(net "GND")
	)
	(via
		(at 135.714994 -269.38351)
		(size 0.4572)
		(drill 0.2032)
		(layers "F.Cu" "B.Cu")
		(net "GND")
	)
	(via
		(at 382.168908 -79.468218)
		(size 0.508)
		(drill 0.254)
		(layers "F.Cu" "B.Cu")
		(net "GND")
	)
	(via
		(at 417.173918 -404.51786)
		(size 0.4572)
		(drill 0.254)
		(layers "F.Cu" "B.Cu")
		(net "GND")
	)
	(via
		(at 311.882282 -297.616626)
		(size 0.4572)
		(drill 0.2032)
		(layers "F.Cu" "B.Cu")
		(net "GND")
	)
	(via
		(at 95.193612 -234.970066)
		(size 0.4572)
		(drill 0.2032)
		(layers "F.Cu" "B.Cu")
		(net "GND")
	)
	(via
		(at 134.815326 -406.370536)
		(size 0.4572)
		(drill 0.254)
		(layers "F.Cu" "B.Cu")
		(net "GND")
	)
	(via
		(at 159.918146 -221.96679)
		(size 0.4572)
		(drill 0.2032)
		(layers "F.Cu" "B.Cu")
		(net "GND")
	)
	(via
		(at 394.349986 -430.299622)
		(size 0.4572)
		(drill 0.2032)
		(layers "F.Cu" "B.Cu")
		(net "GND")
	)
	(via
		(at 421.509952 -323.429376)
		(size 0.4572)
		(drill 0.2032)
		(layers "F.Cu" "B.Cu")
		(net "GND")
	)
	(via
		(at 53.233066 -116.134388)
		(size 0.508)
		(drill 0.254)
		(layers "F.Cu" "B.Cu")
		(net "GND")
	)
	(via
		(at 362.039662 -274.266914)
		(size 0.4572)
		(drill 0.2032)
		(layers "F.Cu" "B.Cu")
		(net "GND")
	)
	(via
		(at 380.835916 -274.266914)
		(size 0.4572)
		(drill 0.2032)
		(layers "F.Cu" "B.Cu")
		(net "GND")
	)
	(via
		(at 299.004482 -207.51673)
		(size 0.4572)
		(drill 0.2032)
		(layers "F.Cu" "B.Cu")
		(net "GND")
	)
	(via
		(at 427.045882 -289.966654)
		(size 0.4572)
		(drill 0.2032)
		(layers "F.Cu" "B.Cu")
		(net "GND")
	)
	(via
		(at 262.519414 -195.616576)
		(size 0.4572)
		(drill 0.2032)
		(layers "F.Cu" "B.Cu")
		(net "GND")
	)
	(via
		(at 157.708346 -311.216802)
		(size 0.4572)
		(drill 0.2032)
		(layers "F.Cu" "B.Cu")
		(net "GND")
	)
	(via
		(at 413.192214 -261.916672)
		(size 0.4572)
		(drill 0.2032)
		(layers "F.Cu" "B.Cu")
		(net "GND")
	)
	(via
		(at 29.082492 -5.596636)
		(size 0.508)
		(drill 0.254)
		(layers "F.Cu" "B.Cu")
		(net "GND")
	)
	(via
		(at 201.35088 -149.824948)
		(size 0.508)
		(drill 0.254)
		(layers "F.Cu" "B.Cu")
		(net "GND")
	)
	(via
		(at 142.658846 -400.224244)
		(size 0.4572)
		(drill 0.254)
		(layers "F.Cu" "B.Cu")
		(net "GND")
	)
	(via
		(at 122.557794 -282.405836)
		(size 0.4572)
		(drill 0.2032)
		(layers "F.Cu" "B.Cu")
		(net "GND")
	)
	(via
		(at 214.615014 -207.51673)
		(size 0.4572)
		(drill 0.2032)
		(layers "F.Cu" "B.Cu")
		(net "GND")
	)
	(via
		(at 450.911214 -214.316564)
		(size 0.4572)
		(drill 0.2032)
		(layers "F.Cu" "B.Cu")
		(net "GND")
	)
	(via
		(at 138.34999 -430.299622)
		(size 0.4572)
		(drill 0.2032)
		(layers "F.Cu" "B.Cu")
		(net "GND")
	)
	(via
		(at 379.316234 -222.761556)
		(size 0.4572)
		(drill 0.2032)
		(layers "F.Cu" "B.Cu")
		(net "GND")
	)
	(via
		(at 22.390608 -4.962652)
		(size 0.508)
		(drill 0.254)
		(layers "F.Cu" "B.Cu")
		(net "GND")
	)
	(via
		(at 172.03293 -102.707948)
		(size 0.508)
		(drill 0.254)
		(layers "F.Cu" "B.Cu")
		(net "GND")
	)
	(via
		(at 183.15432 -351.614994)
		(size 0.49022)
		(drill 0.254)
		(layers "F.Cu" "B.Cu")
		(net "GND")
	)
	(via
		(at 279.816814 -227.066602)
		(size 0.4572)
		(drill 0.2032)
		(layers "F.Cu" "B.Cu")
		(net "GND")
	)
	(via
		(at 435.823614 -290.816792)
		(size 0.4572)
		(drill 0.2032)
		(layers "F.Cu" "B.Cu")
		(net "GND")
	)
	(via
		(at 417.292282 -277.216616)
		(size 0.4572)
		(drill 0.2032)
		(layers "F.Cu" "B.Cu")
		(net "GND")
	)
	(via
		(at 339.098128 -400.858228)
		(size 0.4064)
		(drill 0.2032)
		(layers "F.Cu" "B.Cu")
		(net "GND")
	)
	(via
		(at 455.011282 -305.266598)
		(size 0.4572)
		(drill 0.2032)
		(layers "F.Cu" "B.Cu")
		(net "GND")
	)
	(via
		(at 132.425948 -268.569694)
		(size 0.4572)
		(drill 0.2032)
		(layers "F.Cu" "B.Cu")
		(net "GND")
	)
	(via
		(at 191.983614 -238.116618)
		(size 0.4572)
		(drill 0.2032)
		(layers "F.Cu" "B.Cu")
		(net "GND")
	)
	(via
		(at 55.259224 -167.27805)
		(size 0.49022)
		(drill 0.254)
		(layers "F.Cu" "B.Cu")
		(net "GND")
	)
	(via
		(at 47.808134 -115.328192)
		(size 0.508)
		(drill 0.254)
		(layers "F.Cu" "B.Cu")
		(net "GND")
	)
	(via
		(at 297.782488 -360.83621)
		(size 0.49022)
		(drill 0.254)
		(layers "F.Cu" "B.Cu")
		(net "GND")
	)
	(via
		(at 447.467482 -258.516628)
		(size 0.4572)
		(drill 0.2032)
		(layers "F.Cu" "B.Cu")
		(net "GND")
	)
	(via
		(at 292.332156 -50.141378)
		(size 0.508)
		(drill 0.254)
		(layers "F.Cu" "B.Cu")
		(net "GND")
	)
	(via
		(at 13.345414 -275.516594)
		(size 0.4572)
		(drill 0.2032)
		(layers "F.Cu" "B.Cu")
		(net "GND")
	)
	(via
		(at 194.193414 -258.516628)
		(size 0.4572)
		(drill 0.2032)
		(layers "F.Cu" "B.Cu")
		(net "GND")
	)
	(via
		(at 372.484142 -401.492212)
		(size 0.4572)
		(drill 0.254)
		(layers "F.Cu" "B.Cu")
		(net "GND")
	)
	(via
		(at 283.916882 -204.116686)
		(size 0.4572)
		(drill 0.2032)
		(layers "F.Cu" "B.Cu")
		(net "GND")
	)
	(via
		(at 390.863582 -400.200368)
		(size 0.4572)
		(drill 0.254)
		(layers "F.Cu" "B.Cu")
		(net "GND")
	)
	(via
		(at 254.975614 -258.516628)
		(size 0.4572)
		(drill 0.2032)
		(layers "F.Cu" "B.Cu")
		(net "GND")
	)
	(via
		(at 138.064494 -281.59202)
		(size 0.4572)
		(drill 0.2032)
		(layers "F.Cu" "B.Cu")
		(net "GND")
	)
	(via
		(at 29.666946 -225.36658)
		(size 0.4572)
		(drill 0.2032)
		(layers "F.Cu" "B.Cu")
		(net "GND")
	)
	(via
		(at 331.232764 -336.188812)
		(size 0.508)
		(drill 0.254)
		(layers "F.Cu" "B.Cu")
		(net "GND")
	)
	(via
		(at 53.45049 -409.396184)
		(size 0.4572)
		(drill 0.254)
		(layers "F.Cu" "B.Cu")
		(net "GND")
	)
	(via
		(at 380.415038 -403.249892)
		(size 0.4572)
		(drill 0.254)
		(layers "F.Cu" "B.Cu")
		(net "GND")
	)
	(via
		(at 31.876746 -279.766776)
		(size 0.4572)
		(drill 0.2032)
		(layers "F.Cu" "B.Cu")
		(net "GND")
	)
	(via
		(at 202.971146 -298.466764)
		(size 0.4572)
		(drill 0.2032)
		(layers "F.Cu" "B.Cu")
		(net "GND")
	)
	(via
		(at 378.467366 -78.556358)
		(size 0.6604)
		(drill 0.3302)
		(layers "F.Cu" "B.Cu")
		(net "GND")
	)
	(via
		(at 115.382802 -248.642886)
		(size 0.4572)
		(drill 0.2032)
		(layers "F.Cu" "B.Cu")
		(net "GND")
	)
	(via
		(at 359.245916 -332.56601)
		(size 0.49022)
		(drill 0.254)
		(layers "F.Cu" "B.Cu")
		(net "GND")
	)
	(via
		(at 164.018214 -244.066568)
		(size 0.4572)
		(drill 0.2032)
		(layers "F.Cu" "B.Cu")
		(net "GND")
	)
	(via
		(at 7.035546 -234.716574)
		(size 0.4572)
		(drill 0.2032)
		(layers "F.Cu" "B.Cu")
		(net "GND")
	)
	(via
		(at 172.77588 -127.974598)
		(size 0.508)
		(drill 0.254)
		(layers "F.Cu" "B.Cu")
		(net "GND")
	)
	(via
		(at 101.833426 -358.452674)
		(size 0.508)
		(drill 0.254)
		(layers "F.Cu" "B.Cu")
		(net "GND")
	)
	(via
		(at 453.121014 -251.716794)
		(size 0.4572)
		(drill 0.2032)
		(layers "F.Cu" "B.Cu")
		(net "GND")
	)
	(via
		(at 296.794682 -295.916604)
		(size 0.4572)
		(drill 0.2032)
		(layers "F.Cu" "B.Cu")
		(net "GND")
	)
	(via
		(at 296.794682 -194.766692)
		(size 0.4572)
		(drill 0.2032)
		(layers "F.Cu" "B.Cu")
		(net "GND")
	)
	(via
		(at 66.152014 -261.066788)
		(size 0.4572)
		(drill 0.2032)
		(layers "F.Cu" "B.Cu")
		(net "GND")
	)
	(via
		(at 192.62344 -70.134988)
		(size 0.508)
		(drill 0.254)
		(layers "F.Cu" "B.Cu")
		(net "GND")
	)
	(via
		(at 187.883546 -258.516628)
		(size 0.4572)
		(drill 0.2032)
		(layers "F.Cu" "B.Cu")
		(net "GND")
	)
	(via
		(at 407.858214 -307.816758)
		(size 0.4572)
		(drill 0.2032)
		(layers "F.Cu" "B.Cu")
		(net "GND")
	)
	(via
		(at 379.786134 -230.086662)
		(size 0.4572)
		(drill 0.2032)
		(layers "F.Cu" "B.Cu")
		(net "GND")
	)
	(via
		(at 179.105814 -288.266632)
		(size 0.4572)
		(drill 0.2032)
		(layers "F.Cu" "B.Cu")
		(net "GND")
	)
	(via
		(at 259.075682 -264.466578)
		(size 0.4572)
		(drill 0.2032)
		(layers "F.Cu" "B.Cu")
		(net "GND")
	)
	(via
		(at 46.239684 -323.434456)
		(size 0.4572)
		(drill 0.2032)
		(layers "F.Cu" "B.Cu")
		(net "GND")
	)
	(via
		(at 342.194134 -241.481102)
		(size 0.4572)
		(drill 0.2032)
		(layers "F.Cu" "B.Cu")
		(net "GND")
	)
	(via
		(at 360.520234 -229.272846)
		(size 0.4572)
		(drill 0.2032)
		(layers "F.Cu" "B.Cu")
		(net "GND")
	)
	(via
		(at 443.860428 -30.827218)
		(size 0.508)
		(drill 0.254)
		(layers "F.Cu" "B.Cu")
		(net "GND")
	)
	(via
		(at 266.619482 -266.1666)
		(size 0.4572)
		(drill 0.2032)
		(layers "F.Cu" "B.Cu")
		(net "GND")
	)
	(via
		(at 351.83826 -127.315468)
		(size 0.508)
		(drill 0.254)
		(layers "F.Cu" "B.Cu")
		(net "GND")
	)
	(via
		(at 191.983614 -306.96662)
		(size 0.4572)
		(drill 0.2032)
		(layers "F.Cu" "B.Cu")
		(net "GND")
	)
	(via
		(at 118.218966 -222.761556)
		(size 0.4572)
		(drill 0.2032)
		(layers "F.Cu" "B.Cu")
		(net "GND")
	)
	(via
		(at 262.519414 -206.666592)
		(size 0.4572)
		(drill 0.2032)
		(layers "F.Cu" "B.Cu")
		(net "GND")
	)
	(via
		(at 142.746222 -410.664152)
		(size 0.4572)
		(drill 0.254)
		(layers "F.Cu" "B.Cu")
		(net "GND")
	)
	(via
		(at 261.285482 -213.46668)
		(size 0.4572)
		(drill 0.2032)
		(layers "F.Cu" "B.Cu")
		(net "GND")
	)
	(via
		(at 98.013266 -228.45903)
		(size 0.4572)
		(drill 0.2032)
		(layers "F.Cu" "B.Cu")
		(net "GND")
	)
	(via
		(at 379.956822 -410.664152)
		(size 0.4572)
		(drill 0.254)
		(layers "F.Cu" "B.Cu")
		(net "GND")
	)
	(via
		(at 202.971146 -240.666778)
		(size 0.4572)
		(drill 0.2032)
		(layers "F.Cu" "B.Cu")
		(net "GND")
	)
	(via
		(at 365.044228 -329.300332)
		(size 0.508)
		(drill 0.254)
		(layers "F.Cu" "B.Cu")
		(net "GND")
	)
	(via
		(at 187.883546 -287.416748)
		(size 0.4572)
		(drill 0.2032)
		(layers "F.Cu" "B.Cu")
		(net "GND")
	)
	(via
		(at 466.174836 -386.313934)
		(size 0.508)
		(drill 0.254)
		(layers "F.Cu" "B.Cu")
		(net "GND")
	)
	(via
		(at 289.250882 -232.166668)
		(size 0.4572)
		(drill 0.2032)
		(layers "F.Cu" "B.Cu")
		(net "GND")
	)
	(via
		(at 453.121014 -267.016738)
		(size 0.4572)
		(drill 0.2032)
		(layers "F.Cu" "B.Cu")
		(net "GND")
	)
	(via
		(at 199.527414 -316.316614)
		(size 0.4572)
		(drill 0.2032)
		(layers "F.Cu" "B.Cu")
		(net "GND")
	)
	(via
		(at 165.252146 -227.066602)
		(size 0.4572)
		(drill 0.2032)
		(layers "F.Cu" "B.Cu")
		(net "GND")
	)
	(via
		(at 407.858214 -309.51678)
		(size 0.4572)
		(drill 0.2032)
		(layers "F.Cu" "B.Cu")
		(net "GND")
	)
	(via
		(at 289.250882 -215.166702)
		(size 0.4572)
		(drill 0.2032)
		(layers "F.Cu" "B.Cu")
		(net "GND")
	)
	(via
		(at 323.250052 -425.547282)
		(size 0.4572)
		(drill 0.2032)
		(layers "F.Cu" "B.Cu")
		(net "GND")
	)
	(via
		(at 164.018214 -305.266598)
		(size 0.4572)
		(drill 0.2032)
		(layers "F.Cu" "B.Cu")
		(net "GND")
	)
	(via
		(at 439.923682 -314.616592)
		(size 0.4572)
		(drill 0.2032)
		(layers "F.Cu" "B.Cu")
		(net "GND")
	)
	(via
		(at 292.694614 -223.666558)
		(size 0.4572)
		(drill 0.2032)
		(layers "F.Cu" "B.Cu")
		(net "GND")
	)
	(via
		(at 209.281014 -305.266598)
		(size 0.4572)
		(drill 0.2032)
		(layers "F.Cu" "B.Cu")
		(net "GND")
	)
	(via
		(at 180.339746 -203.266802)
		(size 0.4572)
		(drill 0.2032)
		(layers "F.Cu" "B.Cu")
		(net "GND")
	)
	(via
		(at 122.088148 -266.941808)
		(size 0.4572)
		(drill 0.2032)
		(layers "F.Cu" "B.Cu")
		(net "GND")
	)
	(via
		(at 382.245616 -286.475424)
		(size 0.4572)
		(drill 0.2032)
		(layers "F.Cu" "B.Cu")
		(net "GND")
	)
	(via
		(at 150.228554 -400.858228)
		(size 0.4064)
		(drill 0.2032)
		(layers "F.Cu" "B.Cu")
		(net "GND")
	)
	(via
		(at 108.686346 -329.10272)
		(size 0.508)
		(drill 0.254)
		(layers "F.Cu" "B.Cu")
		(net "GND")
	)
	(via
		(at 176.896014 -216.866724)
		(size 0.4572)
		(drill 0.2032)
		(layers "F.Cu" "B.Cu")
		(net "GND")
	)
	(via
		(at 462.555082 -310.366664)
		(size 0.4572)
		(drill 0.2032)
		(layers "F.Cu" "B.Cu")
		(net "GND")
	)
	(via
		(at 179.105814 -282.316682)
		(size 0.4572)
		(drill 0.2032)
		(layers "F.Cu" "B.Cu")
		(net "GND")
	)
	(via
		(at 374.887744 -366.329214)
		(size 0.508)
		(drill 0.254)
		(layers "F.Cu" "B.Cu")
		(net "GND")
	)
	(via
		(at 428.279814 -199.01662)
		(size 0.4572)
		(drill 0.2032)
		(layers "F.Cu" "B.Cu")
		(net "GND")
	)
	(via
		(at 379.316234 -216.25052)
		(size 0.4572)
		(drill 0.2032)
		(layers "F.Cu" "B.Cu")
		(net "GND")
	)
	(via
		(at 457.221082 -216.866724)
		(size 0.4572)
		(drill 0.2032)
		(layers "F.Cu" "B.Cu")
		(net "GND")
	)
	(via
		(at 56.251856 -152.936702)
		(size 0.508)
		(drill 0.254)
		(layers "F.Cu" "B.Cu")
		(net "GND")
	)
	(via
		(at 370.85778 -243.922804)
		(size 0.4572)
		(drill 0.2032)
		(layers "F.Cu" "B.Cu")
		(net "GND")
	)
	(via
		(at 199.527414 -301.01667)
		(size 0.4572)
		(drill 0.2032)
		(layers "F.Cu" "B.Cu")
		(net "GND")
	)
	(via
		(at 164.018214 -224.516696)
		(size 0.4572)
		(drill 0.2032)
		(layers "F.Cu" "B.Cu")
		(net "GND")
	)
	(via
		(at 48.854614 -286.56661)
		(size 0.4572)
		(drill 0.2032)
		(layers "F.Cu" "B.Cu")
		(net "GND")
	)
	(via
		(at 334.20558 -217.878406)
		(size 0.4572)
		(drill 0.2032)
		(layers "F.Cu" "B.Cu")
		(net "GND")
	)
	(via
		(at 451.685152 -323.429376)
		(size 0.4572)
		(drill 0.2032)
		(layers "F.Cu" "B.Cu")
		(net "GND")
	)
	(via
		(at 266.619482 -247.466612)
		(size 0.4572)
		(drill 0.2032)
		(layers "F.Cu" "B.Cu")
		(net "GND")
	)
	(via
		(at 409.349956 -428.851314)
		(size 0.4572)
		(drill 0.2032)
		(layers "F.Cu" "B.Cu")
		(net "GND")
	)
	(via
		(at 128.54305 -358.111806)
		(size 0.508)
		(drill 0.254)
		(layers "F.Cu" "B.Cu")
		(net "GND")
	)
	(via
		(at 129.050034 -410.030168)
		(size 0.4064)
		(drill 0.2032)
		(layers "F.Cu" "B.Cu")
		(net "GND")
	)
	(via
		(at 126.207012 -236.597952)
		(size 0.4572)
		(drill 0.2032)
		(layers "F.Cu" "B.Cu")
		(net "GND")
	)
	(via
		(at 311.882282 -196.466714)
		(size 0.4572)
		(drill 0.2032)
		(layers "F.Cu" "B.Cu")
		(net "GND")
	)
	(via
		(at 323.781928 -403.883876)
		(size 0.4064)
		(drill 0.2032)
		(layers "F.Cu" "B.Cu")
		(net "GND")
	)
	(via
		(at 9.0424 -57.75452)
		(size 0.508)
		(drill 0.254)
		(layers "F.Cu" "B.Cu")
		(net "GND")
	)
	(via
		(at 202.971146 -313.766708)
		(size 0.4572)
		(drill 0.2032)
		(layers "F.Cu" "B.Cu")
		(net "GND")
	)
	(via
		(at 177.088038 -417.745418)
		(size 0.508)
		(drill 0.254)
		(layers "F.Cu" "B.Cu")
		(net "GND")
	)
	(via
		(at 257.185414 -212.616796)
		(size 0.4572)
		(drill 0.2032)
		(layers "F.Cu" "B.Cu")
		(net "GND")
	)
	(via
		(at 434.589682 -286.56661)
		(size 0.4572)
		(drill 0.2032)
		(layers "F.Cu" "B.Cu")
		(net "GND")
	)
	(via
		(at 133.556502 -407.638504)
		(size 0.4572)
		(drill 0.254)
		(layers "F.Cu" "B.Cu")
		(net "GND")
	)
	(via
		(at 144.309846 -55.350664)
		(size 0.508)
		(drill 0.254)
		(layers "F.Cu" "B.Cu")
		(net "GND")
	)
	(via
		(at 261.285482 -277.216616)
		(size 0.4572)
		(drill 0.2032)
		(layers "F.Cu" "B.Cu")
		(net "GND")
	)
	(via
		(at 373.830342 -409.396184)
		(size 0.4572)
		(drill 0.254)
		(layers "F.Cu" "B.Cu")
		(net "GND")
	)
	(via
		(at 191.983614 -200.716642)
		(size 0.4572)
		(drill 0.2032)
		(layers "F.Cu" "B.Cu")
		(net "GND")
	)
	(via
		(at 368.889534 -240.704116)
		(size 0.4572)
		(drill 0.2032)
		(layers "F.Cu" "B.Cu")
		(net "GND")
	)
	(via
		(at 41.310814 -205.816708)
		(size 0.4572)
		(drill 0.2032)
		(layers "F.Cu" "B.Cu")
		(net "GND")
	)
	(via
		(at 365.042958 -183.12511)
		(size 0.508)
		(drill 0.254)
		(layers "F.Cu" "B.Cu")
		(net "GND")
	)
	(via
		(at 334.67548 -239.853216)
		(size 0.4318)
		(drill 0.2032)
		(layers "F.Cu" "B.Cu")
		(net "GND")
	)
	(via
		(at 203.598018 -130.287268)
		(size 0.508)
		(drill 0.254)
		(layers "F.Cu" "B.Cu")
		(net "GND")
	)
	(via
		(at 37.44849 -175.464978)
		(size 0.508)
		(drill 0.254)
		(layers "F.Cu" "B.Cu")
		(net "GND")
	)
	(via
		(at 41.3385 -130.175508)
		(size 0.508)
		(drill 0.254)
		(layers "F.Cu" "B.Cu")
		(net "GND")
	)
	(via
		(at 314.094622 -53.228748)
		(size 0.508)
		(drill 0.254)
		(layers "F.Cu" "B.Cu")
		(net "GND")
	)
	(via
		(at 325.225156 -403.249892)
		(size 0.4572)
		(drill 0.254)
		(layers "F.Cu" "B.Cu")
		(net "GND")
	)
	(via
		(at 16.789146 -217.716608)
		(size 0.4572)
		(drill 0.2032)
		(layers "F.Cu" "B.Cu")
		(net "GND")
	)
	(via
		(at 285.150814 -298.466764)
		(size 0.4572)
		(drill 0.2032)
		(layers "F.Cu" "B.Cu")
		(net "GND")
	)
	(via
		(at 306.92471 -68.872354)
		(size 0.508)
		(drill 0.254)
		(layers "F.Cu" "B.Cu")
		(net "GND")
	)
	(via
		(at 2.764536 -117.270022)
		(size 0.508)
		(drill 0.254)
		(layers "F.Cu" "B.Cu")
		(net "GND")
	)
	(via
		(at 311.882282 -295.916604)
		(size 0.4572)
		(drill 0.2032)
		(layers "F.Cu" "B.Cu")
		(net "GND")
	)
	(via
		(at 33.767014 -204.116686)
		(size 0.4572)
		(drill 0.2032)
		(layers "F.Cu" "B.Cu")
		(net "GND")
	)
	(via
		(at 276.373082 -258.516628)
		(size 0.4572)
		(drill 0.2032)
		(layers "F.Cu" "B.Cu")
		(net "GND")
	)
	(via
		(at 415.402014 -261.916672)
		(size 0.4572)
		(drill 0.2032)
		(layers "F.Cu" "B.Cu")
		(net "GND")
	)
	(via
		(at 99.532948 -260.430772)
		(size 0.4572)
		(drill 0.2032)
		(layers "F.Cu" "B.Cu")
		(net "GND")
	)
	(via
		(at 289.250882 -230.466646)
		(size 0.4572)
		(drill 0.2032)
		(layers "F.Cu" "B.Cu")
		(net "GND")
	)
	(via
		(at 348.412562 -283.219906)
		(size 0.4572)
		(drill 0.2032)
		(layers "F.Cu" "B.Cu")
		(net "GND")
	)
	(via
		(at 26.223214 -245.76659)
		(size 0.4572)
		(drill 0.2032)
		(layers "F.Cu" "B.Cu")
		(net "GND")
	)
	(via
		(at 369.558062 -280.778204)
		(size 0.4572)
		(drill 0.2032)
		(layers "F.Cu" "B.Cu")
		(net "GND")
	)
	(via
		(at 85.887306 -409.396184)
		(size 0.4572)
		(drill 0.254)
		(layers "F.Cu" "B.Cu")
		(net "GND")
	)
	(via
		(at 214.4268 -106.3752)
		(size 0.508)
		(drill 0.254)
		(layers "F.Cu" "B.Cu")
		(net "GND")
	)
	(via
		(at 186.649614 -267.866622)
		(size 0.4572)
		(drill 0.2032)
		(layers "F.Cu" "B.Cu")
		(net "GND")
	)
	(via
		(at 445.0588 -50.231548)
		(size 0.508)
		(drill 0.254)
		(layers "F.Cu" "B.Cu")
		(net "GND")
	)
	(via
		(at 99.532948 -263.686544)
		(size 0.4572)
		(drill 0.2032)
		(layers "F.Cu" "B.Cu")
		(net "GND")
	)
	(via
		(at 464.764882 -241.516662)
		(size 0.4572)
		(drill 0.2032)
		(layers "F.Cu" "B.Cu")
		(net "GND")
	)
	(via
		(at 439.923682 -198.166736)
		(size 0.4572)
		(drill 0.2032)
		(layers "F.Cu" "B.Cu")
		(net "GND")
	)
	(via
		(at 344.183462 -257.98907)
		(size 0.4572)
		(drill 0.2032)
		(layers "F.Cu" "B.Cu")
		(net "GND")
	)
	(via
		(at 332.61046 -401.492212)
		(size 0.4572)
		(drill 0.254)
		(layers "F.Cu" "B.Cu")
		(net "GND")
	)
	(via
		(at 419.761416 -312.91657)
		(size 0.4572)
		(drill 0.2032)
		(layers "F.Cu" "B.Cu")
		(net "GND")
	)
	(via
		(at 204.873352 -89.178638)
		(size 0.508)
		(drill 0.254)
		(layers "F.Cu" "B.Cu")
		(net "GND")
	)
	(via
		(at 333.315564 -217.924888)
		(size 0.4572)
		(drill 0.2032)
		(layers "F.Cu" "B.Cu")
		(net "GND")
	)
	(via
		(at 327.250044 -436.347362)
		(size 0.4572)
		(drill 0.2032)
		(layers "F.Cu" "B.Cu")
		(net "GND")
	)
	(via
		(at 128.666494 -289.807142)
		(size 0.4572)
		(drill 0.2032)
		(layers "F.Cu" "B.Cu")
		(net "GND")
	)
	(via
		(at 418.79393 -400.858228)
		(size 0.4064)
		(drill 0.2032)
		(layers "F.Cu" "B.Cu")
		(net "GND")
	)
	(via
		(at 435.823614 -273.816572)
		(size 0.4572)
		(drill 0.2032)
		(layers "F.Cu" "B.Cu")
		(net "GND")
	)
	(via
		(at 274.163282 -207.51673)
		(size 0.4572)
		(drill 0.2032)
		(layers "F.Cu" "B.Cu")
		(net "GND")
	)
	(via
		(at 187.355734 -122.175524)
		(size 0.4572)
		(drill 0.254)
		(layers "F.Cu" "B.Cu")
		(net "GND")
	)
	(via
		(at 178.289204 -49.800002)
		(size 0.508)
		(drill 0.254)
		(layers "F.Cu" "B.Cu")
		(net "GND")
	)
	(via
		(at 445.577214 -240.666778)
		(size 0.4572)
		(drill 0.2032)
		(layers "F.Cu" "B.Cu")
		(net "GND")
	)
	(via
		(at 304.338482 -282.316682)
		(size 0.4572)
		(drill 0.2032)
		(layers "F.Cu" "B.Cu")
		(net "GND")
	)
	(via
		(at 458.455014 -251.716794)
		(size 0.4572)
		(drill 0.2032)
		(layers "F.Cu" "B.Cu")
		(net "GND")
	)
	(via
		(at 116.127784 -297.19778)
		(size 0.508)
		(drill 0.254)
		(layers "F.Cu" "B.Cu")
		(net "GND")
	)
	(via
		(at 303.5554 -55.286148)
		(size 0.508)
		(drill 0.254)
		(layers "F.Cu" "B.Cu")
		(net "GND")
	)
	(via
		(at 438.033414 -197.316598)
		(size 0.4572)
		(drill 0.2032)
		(layers "F.Cu" "B.Cu")
		(net "GND")
	)
	(via
		(at 415.967418 -149.312376)
		(size 0.508)
		(drill 0.254)
		(layers "F.Cu" "B.Cu")
		(net "GND")
	)
	(via
		(at 99.422966 -230.900478)
		(size 0.4572)
		(drill 0.2032)
		(layers "F.Cu" "B.Cu")
		(net "GND")
	)
	(via
		(at 96.243394 -266.128246)
		(size 0.4572)
		(drill 0.2032)
		(layers "F.Cu" "B.Cu")
		(net "GND")
	)
	(via
		(at 277.607014 -289.11677)
		(size 0.4572)
		(drill 0.2032)
		(layers "F.Cu" "B.Cu")
		(net "GND")
	)
	(via
		(at 274.163282 -210.066636)
		(size 0.4572)
		(drill 0.2032)
		(layers "F.Cu" "B.Cu")
		(net "GND")
	)
	(via
		(at 125.737366 -248.806208)
		(size 0.4572)
		(drill 0.2032)
		(layers "F.Cu" "B.Cu")
		(net "GND")
	)
	(via
		(at 457.221082 -235.566712)
		(size 0.4572)
		(drill 0.2032)
		(layers "F.Cu" "B.Cu")
		(net "GND")
	)
	(via
		(at 264.729214 -244.916706)
		(size 0.4572)
		(drill 0.2032)
		(layers "F.Cu" "B.Cu")
		(net "GND")
	)
	(via
		(at 71.250048 -425.547282)
		(size 0.4572)
		(drill 0.2032)
		(layers "F.Cu" "B.Cu")
		(net "GND")
	)
	(via
		(at 417.292282 -314.616592)
		(size 0.4572)
		(drill 0.2032)
		(layers "F.Cu" "B.Cu")
		(net "GND")
	)
	(via
		(at 19.44751 -182.359046)
		(size 0.508)
		(drill 0.254)
		(layers "F.Cu" "B.Cu")
		(net "GND")
	)
	(via
		(at 359.752392 -335.704434)
		(size 0.49022)
		(drill 0.254)
		(layers "F.Cu" "B.Cu")
		(net "GND")
	)
	(via
		(at 207.071214 -233.86669)
		(size 0.4572)
		(drill 0.2032)
		(layers "F.Cu" "B.Cu")
		(net "GND")
	)
	(via
		(at 350.807274 -172.790612)
		(size 0.508)
		(drill 0.254)
		(layers "F.Cu" "B.Cu")
		(net "GND")
	)
	(via
		(at 307.566314 -273.816572)
		(size 0.4572)
		(drill 0.2032)
		(layers "F.Cu" "B.Cu")
		(net "GND")
	)
	(via
		(at 308.465728 -403.883876)
		(size 0.4064)
		(drill 0.2032)
		(layers "F.Cu" "B.Cu")
		(net "GND")
	)
	(via
		(at 370.0018 -93.889068)
		(size 0.508)
		(drill 0.254)
		(layers "F.Cu" "B.Cu")
		(net "GND")
	)
	(via
		(at 276.373082 -224.516696)
		(size 0.4572)
		(drill 0.2032)
		(layers "F.Cu" "B.Cu")
		(net "GND")
	)
	(via
		(at 89.554812 -236.597952)
		(size 0.4572)
		(drill 0.2032)
		(layers "F.Cu" "B.Cu")
		(net "GND")
	)
	(via
		(at 356.373684 -245.347236)
		(size 0.4572)
		(drill 0.2032)
		(layers "F.Cu" "B.Cu")
		(net "GND")
	)
	(via
		(at 415.402014 -251.716794)
		(size 0.4572)
		(drill 0.2032)
		(layers "F.Cu" "B.Cu")
		(net "GND")
	)
	(via
		(at 393.926822 -403.249892)
		(size 0.4572)
		(drill 0.254)
		(layers "F.Cu" "B.Cu")
		(net "GND")
	)
	(via
		(at 201.737214 -241.516662)
		(size 0.4572)
		(drill 0.2032)
		(layers "F.Cu" "B.Cu")
		(net "GND")
	)
	(via
		(at 128.549908 -358.75468)
		(size 0.508)
		(drill 0.254)
		(layers "F.Cu" "B.Cu")
		(net "GND")
	)
	(via
		(at 56.912256 -144.300702)
		(size 0.508)
		(drill 0.254)
		(layers "F.Cu" "B.Cu")
		(net "GND")
	)
	(via
		(at 346.250006 -432.451256)
		(size 0.4572)
		(drill 0.2032)
		(layers "F.Cu" "B.Cu")
		(net "GND")
	)
	(via
		(at 50.936906 -17.61236)
		(size 0.508)
		(drill 0.254)
		(layers "F.Cu" "B.Cu")
		(net "GND")
	)
	(via
		(at 7.035546 -217.716608)
		(size 0.4572)
		(drill 0.2032)
		(layers "F.Cu" "B.Cu")
		(net "GND")
	)
	(via
		(at 173.465998 -351.614994)
		(size 0.49022)
		(drill 0.254)
		(layers "F.Cu" "B.Cu")
		(net "GND")
	)
	(via
		(at 63.260732 -0.76454)
		(size 0.508)
		(drill 0.254)
		(layers "F.Cu" "B.Cu")
		(net "GND")
	)
	(via
		(at 171.562014 -239.81664)
		(size 0.4572)
		(drill 0.2032)
		(layers "F.Cu" "B.Cu")
		(net "GND")
	)
	(via
		(at 385.686554 -347.959426)
		(size 0.508)
		(drill 0.254)
		(layers "F.Cu" "B.Cu")
		(net "GND")
	)
	(via
		(at 438.270142 -120.614186)
		(size 0.508)
		(drill 0.254)
		(layers "F.Cu" "B.Cu")
		(net "GND")
	)
	(via
		(at 292.694614 -296.766742)
		(size 0.4572)
		(drill 0.2032)
		(layers "F.Cu" "B.Cu")
		(net "GND")
	)
	(via
		(at 413.192214 -234.716574)
		(size 0.4572)
		(drill 0.2032)
		(layers "F.Cu" "B.Cu")
		(net "GND")
	)
	(via
		(at 420.736014 -304.416714)
		(size 0.4572)
		(drill 0.2032)
		(layers "F.Cu" "B.Cu")
		(net "GND")
	)
	(via
		(at 445.617092 -25.477978)
		(size 0.508)
		(drill 0.254)
		(layers "F.Cu" "B.Cu")
		(net "GND")
	)
	(via
		(at 432.379882 -264.466578)
		(size 0.4572)
		(drill 0.2032)
		(layers "F.Cu" "B.Cu")
		(net "GND")
	)
	(via
		(at 276.373082 -245.76659)
		(size 0.4572)
		(drill 0.2032)
		(layers "F.Cu" "B.Cu")
		(net "GND")
	)
	(via
		(at 147.188174 -51.404012)
		(size 0.508)
		(drill 0.254)
		(layers "F.Cu" "B.Cu")
		(net "GND")
	)
	(via
		(at 172.795946 -246.616728)
		(size 0.4572)
		(drill 0.2032)
		(layers "F.Cu" "B.Cu")
		(net "GND")
	)
	(via
		(at 118.798848 -285.661354)
		(size 0.4572)
		(drill 0.2032)
		(layers "F.Cu" "B.Cu")
		(net "GND")
	)
	(via
		(at 176.896014 -232.166668)
		(size 0.4572)
		(drill 0.2032)
		(layers "F.Cu" "B.Cu")
		(net "GND")
	)
	(via
		(at 376.21337 -355.331268)
		(size 0.508)
		(drill 0.254)
		(layers "F.Cu" "B.Cu")
		(net "GND")
	)
	(via
		(at 264.729214 -246.616728)
		(size 0.4572)
		(drill 0.2032)
		(layers "F.Cu" "B.Cu")
		(net "GND")
	)
	(via
		(at 306.548282 -232.166668)
		(size 0.4572)
		(drill 0.2032)
		(layers "F.Cu" "B.Cu")
		(net "GND")
	)
	(via
		(at 162.842702 -403.249892)
		(size 0.4572)
		(drill 0.254)
		(layers "F.Cu" "B.Cu")
		(net "GND")
	)
	(via
		(at 214.615014 -299.316648)
		(size 0.4572)
		(drill 0.2032)
		(layers "F.Cu" "B.Cu")
		(net "GND")
	)
	(via
		(at 180.36032 -351.614994)
		(size 0.49022)
		(drill 0.254)
		(layers "F.Cu" "B.Cu")
		(net "GND")
	)
	(via
		(at 182.549546 -279.766776)
		(size 0.4572)
		(drill 0.2032)
		(layers "F.Cu" "B.Cu")
		(net "GND")
	)
	(via
		(at 415.402014 -199.01662)
		(size 0.4572)
		(drill 0.2032)
		(layers "F.Cu" "B.Cu")
		(net "GND")
	)
	(via
		(at 257.185414 -268.71676)
		(size 0.4572)
		(drill 0.2032)
		(layers "F.Cu" "B.Cu")
		(net "GND")
	)
	(via
		(at 60.035186 -403.249892)
		(size 0.4572)
		(drill 0.254)
		(layers "F.Cu" "B.Cu")
		(net "GND")
	)
	(via
		(at 190.093346 -221.96679)
		(size 0.4572)
		(drill 0.2032)
		(layers "F.Cu" "B.Cu")
		(net "GND")
	)
	(via
		(at 179.105814 -205.816708)
		(size 0.4572)
		(drill 0.2032)
		(layers "F.Cu" "B.Cu")
		(net "GND")
	)
	(via
		(at 31.876746 -203.266802)
		(size 0.4572)
		(drill 0.2032)
		(layers "F.Cu" "B.Cu")
		(net "GND")
	)
	(via
		(at 94.98965 -400.224244)
		(size 0.4572)
		(drill 0.254)
		(layers "F.Cu" "B.Cu")
		(net "GND")
	)
	(via
		(at 369.448334 -217.064336)
		(size 0.4572)
		(drill 0.2032)
		(layers "F.Cu" "B.Cu")
		(net "GND")
	)
	(via
		(at 364.383828 -329.300332)
		(size 0.508)
		(drill 0.254)
		(layers "F.Cu" "B.Cu")
		(net "GND")
	)
	(via
		(at 165.808914 -410.030168)
		(size 0.4064)
		(drill 0.2032)
		(layers "F.Cu" "B.Cu")
		(net "GND")
	)
	(via
		(at 182.549546 -285.716726)
		(size 0.4572)
		(drill 0.2032)
		(layers "F.Cu" "B.Cu")
		(net "GND")
	)
	(via
		(at 26.496772 -404.445216)
		(size 0.508)
		(drill 0.254)
		(layers "F.Cu" "B.Cu")
		(net "GND")
	)
	(via
		(at 92.365322 -333.173324)
		(size 0.508)
		(drill 0.254)
		(layers "F.Cu" "B.Cu")
		(net "GND")
	)
	(via
		(at 190.093346 -315.46673)
		(size 0.4572)
		(drill 0.2032)
		(layers "F.Cu" "B.Cu")
		(net "GND")
	)
	(via
		(at 129.026412 -243.108988)
		(size 0.4572)
		(drill 0.2032)
		(layers "F.Cu" "B.Cu")
		(net "GND")
	)
	(via
		(at 405.648414 -267.016738)
		(size 0.4572)
		(drill 0.2032)
		(layers "F.Cu" "B.Cu")
		(net "GND")
	)
	(via
		(at 420.736014 -276.366732)
		(size 0.4572)
		(drill 0.2032)
		(layers "F.Cu" "B.Cu")
		(net "GND")
	)
	(via
		(at 207.071214 -226.216718)
		(size 0.4572)
		(drill 0.2032)
		(layers "F.Cu" "B.Cu")
		(net "GND")
	)
	(via
		(at 86.250018 -433.747164)
		(size 0.4572)
		(drill 0.2032)
		(layers "F.Cu" "B.Cu")
		(net "GND")
	)
	(via
		(at 368.889534 -240.119916)
		(size 0.4572)
		(drill 0.2032)
		(layers "F.Cu" "B.Cu")
		(net "GND")
	)
	(via
		(at 157.708346 -242.3668)
		(size 0.4572)
		(drill 0.2032)
		(layers "F.Cu" "B.Cu")
		(net "GND")
	)
	(via
		(at 427.045882 -249.166634)
		(size 0.4572)
		(drill 0.2032)
		(layers "F.Cu" "B.Cu")
		(net "GND")
	)
	(via
		(at 150.60168 -82.895948)
		(size 0.508)
		(drill 0.254)
		(layers "F.Cu" "B.Cu")
		(net "GND")
	)
	(via
		(at 428.279814 -208.366614)
		(size 0.4572)
		(drill 0.2032)
		(layers "F.Cu" "B.Cu")
		(net "GND")
	)
	(via
		(at 336.929222 -63.388748)
		(size 0.508)
		(drill 0.254)
		(layers "F.Cu" "B.Cu")
		(net "GND")
	)
	(via
		(at 144.463262 -404.51786)
		(size 0.4572)
		(drill 0.254)
		(layers "F.Cu" "B.Cu")
		(net "GND")
	)
	(via
		(at 409.748482 -213.46668)
		(size 0.4572)
		(drill 0.2032)
		(layers "F.Cu" "B.Cu")
		(net "GND")
	)
	(via
		(at 300.022514 -273.816572)
		(size 0.4572)
		(drill 0.2032)
		(layers "F.Cu" "B.Cu")
		(net "GND")
	)
	(via
		(at 70.861936 -7.215124)
		(size 0.508)
		(drill 0.254)
		(layers "F.Cu" "B.Cu")
		(net "GND")
	)
	(via
		(at 180.955696 -115.775486)
		(size 0.4572)
		(drill 0.254)
		(layers "F.Cu" "B.Cu")
		(net "GND")
	)
	(via
		(at 89.664794 -257.98907)
		(size 0.4572)
		(drill 0.2032)
		(layers "F.Cu" "B.Cu")
		(net "GND")
	)
	(via
		(at 24.332946 -292.516814)
		(size 0.4572)
		(drill 0.2032)
		(layers "F.Cu" "B.Cu")
		(net "GND")
	)
	(via
		(at 197.637146 -203.266802)
		(size 0.4572)
		(drill 0.2032)
		(layers "F.Cu" "B.Cu")
		(net "GND")
	)
	(via
		(at 292.169088 -162.139884)
		(size 0.508)
		(drill 0.254)
		(layers "F.Cu" "B.Cu")
		(net "GND")
	)
	(via
		(at 374.199912 -160.435036)
		(size 0.508)
		(drill 0.254)
		(layers "F.Cu" "B.Cu")
		(net "GND")
	)
	(via
		(at 292.694614 -311.216802)
		(size 0.4572)
		(drill 0.2032)
		(layers "F.Cu" "B.Cu")
		(net "GND")
	)
	(via
		(at 147.500848 -54.832758)
		(size 0.508)
		(drill 0.254)
		(layers "F.Cu" "B.Cu")
		(net "GND")
	)
	(via
		(at 167.684196 -236.416596)
		(size 0.4572)
		(drill 0.2032)
		(layers "F.Cu" "B.Cu")
		(net "GND")
	)
	(via
		(at 201.737214 -308.666642)
		(size 0.4572)
		(drill 0.2032)
		(layers "F.Cu" "B.Cu")
		(net "GND")
	)
	(via
		(at 52.298346 -195.616576)
		(size 0.4572)
		(drill 0.2032)
		(layers "F.Cu" "B.Cu")
		(net "GND")
	)
	(via
		(at 161.808414 -269.566644)
		(size 0.4572)
		(drill 0.2032)
		(layers "F.Cu" "B.Cu")
		(net "GND")
	)
	(via
		(at 199.527414 -244.066568)
		(size 0.4572)
		(drill 0.2032)
		(layers "F.Cu" "B.Cu")
		(net "GND")
	)
	(via
		(at 100.525834 -331.08392)
		(size 0.508)
		(drill 0.254)
		(layers "F.Cu" "B.Cu")
		(net "GND")
	)
	(via
		(at 65.70345 -407.638504)
		(size 0.4572)
		(drill 0.254)
		(layers "F.Cu" "B.Cu")
		(net "GND")
	)
	(via
		(at 380.72568 -236.597952)
		(size 0.4572)
		(drill 0.2032)
		(layers "F.Cu" "B.Cu")
		(net "GND")
	)
	(via
		(at 212.724746 -225.36658)
		(size 0.4572)
		(drill 0.2032)
		(layers "F.Cu" "B.Cu")
		(net "GND")
	)
	(via
		(at 420.883588 -19.759422)
		(size 0.508)
		(drill 0.254)
		(layers "F.Cu" "B.Cu")
		(net "GND")
	)
	(via
		(at 2.764536 -168.070022)
		(size 0.508)
		(drill 0.254)
		(layers "F.Cu" "B.Cu")
		(net "GND")
	)
	(via
		(at 415.648648 -162.166554)
		(size 0.49022)
		(drill 0.254)
		(layers "F.Cu" "B.Cu")
		(net "GND")
	)
	(via
		(at 199.527414 -230.466646)
		(size 0.4572)
		(drill 0.2032)
		(layers "F.Cu" "B.Cu")
		(net "GND")
	)
	(via
		(at 110.23092 -243.109242)
		(size 0.4572)
		(drill 0.2032)
		(layers "F.Cu" "B.Cu")
		(net "GND")
	)
	(via
		(at 175.005746 -304.416714)
		(size 0.4572)
		(drill 0.2032)
		(layers "F.Cu" "B.Cu")
		(net "GND")
	)
	(via
		(at 419.272466 -358.754172)
		(size 0.508)
		(drill 0.254)
		(layers "F.Cu" "B.Cu")
		(net "GND")
	)
	(via
		(at 343.713816 -279.964134)
		(size 0.4572)
		(drill 0.2032)
		(layers "F.Cu" "B.Cu")
		(net "GND")
	)
	(via
		(at 274.163282 -249.166634)
		(size 0.4572)
		(drill 0.2032)
		(layers "F.Cu" "B.Cu")
		(net "GND")
	)
	(via
		(at 385.065016 -265.314176)
		(size 0.4318)
		(drill 0.2032)
		(layers "F.Cu" "B.Cu")
		(net "GND")
	)
	(via
		(at 299.004482 -233.86669)
		(size 0.4572)
		(drill 0.2032)
		(layers "F.Cu" "B.Cu")
		(net "GND")
	)
	(via
		(at 214.615014 -198.166736)
		(size 0.4572)
		(drill 0.2032)
		(layers "F.Cu" "B.Cu")
		(net "GND")
	)
	(via
		(at 186.649614 -301.01667)
		(size 0.4572)
		(drill 0.2032)
		(layers "F.Cu" "B.Cu")
		(net "GND")
	)
	(via
		(at 423.677588 -16.967454)
		(size 0.508)
		(drill 0.254)
		(layers "F.Cu" "B.Cu")
		(net "GND")
	)
	(via
		(at 119.738394 -280.778204)
		(size 0.4572)
		(drill 0.2032)
		(layers "F.Cu" "B.Cu")
		(net "GND")
	)
	(via
		(at 42.759884 -323.434456)
		(size 0.4572)
		(drill 0.2032)
		(layers "F.Cu" "B.Cu")
		(net "GND")
	)
	(via
		(at 354.991416 -270.19758)
		(size 0.4572)
		(drill 0.2032)
		(layers "F.Cu" "B.Cu")
		(net "GND")
	)
	(via
		(at 430.489614 -279.766776)
		(size 0.4572)
		(drill 0.2032)
		(layers "F.Cu" "B.Cu")
		(net "GND")
	)
	(via
		(at 157.349952 -426.54728)
		(size 0.4572)
		(drill 0.2032)
		(layers "F.Cu" "B.Cu")
		(net "GND")
	)
	(via
		(at 126.787148 -278.336502)
		(size 0.4572)
		(drill 0.2032)
		(layers "F.Cu" "B.Cu")
		(net "GND")
	)
	(via
		(at 366.738662 -272.639282)
		(size 0.4572)
		(drill 0.2032)
		(layers "F.Cu" "B.Cu")
		(net "GND")
	)
	(via
		(at 31.423864 -4.328668)
		(size 0.508)
		(drill 0.254)
		(layers "F.Cu" "B.Cu")
		(net "GND")
	)
	(via
		(at 259.075682 -247.466612)
		(size 0.4572)
		(drill 0.2032)
		(layers "F.Cu" "B.Cu")
		(net "GND")
	)
	(via
		(at 419.643052 -133.114034)
		(size 0.508)
		(drill 0.254)
		(layers "F.Cu" "B.Cu")
		(net "GND")
	)
	(via
		(at 270.063214 -227.066602)
		(size 0.4572)
		(drill 0.2032)
		(layers "F.Cu" "B.Cu")
		(net "GND")
	)
	(via
		(at 338.250022 -427.699678)
		(size 0.4572)
		(drill 0.2032)
		(layers "F.Cu" "B.Cu")
		(net "GND")
	)
	(via
		(at 318.64046 -409.396184)
		(size 0.4572)
		(drill 0.254)
		(layers "F.Cu" "B.Cu")
		(net "GND")
	)
	(via
		(at 272.273014 -276.366732)
		(size 0.4572)
		(drill 0.2032)
		(layers "F.Cu" "B.Cu")
		(net "GND")
	)
	(via
		(at 343.547954 -48.449992)
		(size 0.4572)
		(drill 0.2032)
		(layers "F.Cu" "B.Cu")
		(net "GND")
	)
	(via
		(at 464.53552 -418.23513)
		(size 0.508)
		(drill 0.254)
		(layers "F.Cu" "B.Cu")
		(net "GND")
	)
	(via
		(at 311.882282 -316.316614)
		(size 0.4572)
		(drill 0.2032)
		(layers "F.Cu" "B.Cu")
		(net "GND")
	)
	(via
		(at 370.85778 -240.667286)
		(size 0.4572)
		(drill 0.2032)
		(layers "F.Cu" "B.Cu")
		(net "GND")
	)
	(via
		(at 109.625384 -98.959416)
		(size 0.508)
		(drill 0.254)
		(layers "F.Cu" "B.Cu")
		(net "GND")
	)
	(via
		(at 439.923682 -250.866656)
		(size 0.4572)
		(drill 0.2032)
		(layers "F.Cu" "B.Cu")
		(net "GND")
	)
	(via
		(at 338.293964 -441.225432)
		(size 0.508)
		(drill 0.254)
		(layers "F.Cu" "B.Cu")
		(net "GND")
	)
	(via
		(at 411.958282 -194.766692)
		(size 0.4572)
		(drill 0.2032)
		(layers "F.Cu" "B.Cu")
		(net "GND")
	)
	(via
		(at 424.836082 -266.1666)
		(size 0.4572)
		(drill 0.2032)
		(layers "F.Cu" "B.Cu")
		(net "GND")
	)
	(via
		(at 16.789146 -283.166566)
		(size 0.4572)
		(drill 0.2032)
		(layers "F.Cu" "B.Cu")
		(net "GND")
	)
	(via
		(at 422.945814 -315.46673)
		(size 0.4572)
		(drill 0.2032)
		(layers "F.Cu" "B.Cu")
		(net "GND")
	)
	(via
		(at 416.715702 -407.638504)
		(size 0.4572)
		(drill 0.254)
		(layers "F.Cu" "B.Cu")
		(net "GND")
	)
	(via
		(at 90.25001 -438.499758)
		(size 0.4572)
		(drill 0.2032)
		(layers "F.Cu" "B.Cu")
		(net "GND")
	)
	(via
		(at 171.562014 -269.566644)
		(size 0.4572)
		(drill 0.2032)
		(layers "F.Cu" "B.Cu")
		(net "GND")
	)
	(via
		(at 289.250882 -282.316682)
		(size 0.4572)
		(drill 0.2032)
		(layers "F.Cu" "B.Cu")
		(net "GND")
	)
	(via
		(at 268.829282 -244.066568)
		(size 0.4572)
		(drill 0.2032)
		(layers "F.Cu" "B.Cu")
		(net "GND")
	)
	(via
		(at 355.461062 -266.128246)
		(size 0.4572)
		(drill 0.2032)
		(layers "F.Cu" "B.Cu")
		(net "GND")
	)
	(via
		(at 434.02504 -124.512578)
		(size 0.508)
		(drill 0.254)
		(layers "F.Cu" "B.Cu")
		(net "GND")
	)
	(via
		(at 195.427346 -217.716608)
		(size 0.4572)
		(drill 0.2032)
		(layers "F.Cu" "B.Cu")
		(net "GND")
	)
	(via
		(at 462.555082 -306.96662)
		(size 0.4572)
		(drill 0.2032)
		(layers "F.Cu" "B.Cu")
		(net "GND")
	)
	(via
		(at 300.663864 -361.629452)
		(size 0.49022)
		(drill 0.254)
		(layers "F.Cu" "B.Cu")
		(net "GND")
	)
	(via
		(at 39.552372 -351.608644)
		(size 0.49022)
		(drill 0.254)
		(layers "F.Cu" "B.Cu")
		(net "GND")
	)
	(via
		(at 330.89342 -410.664152)
		(size 0.4572)
		(drill 0.254)
		(layers "F.Cu" "B.Cu")
		(net "GND")
	)
	(via
		(at 397.35125 -400.858228)
		(size 0.4064)
		(drill 0.2032)
		(layers "F.Cu" "B.Cu")
		(net "GND")
	)
	(via
		(at 179.105814 -301.01667)
		(size 0.4572)
		(drill 0.2032)
		(layers "F.Cu" "B.Cu")
		(net "GND")
	)
	(via
		(at 59.842146 -251.716794)
		(size 0.4572)
		(drill 0.2032)
		(layers "F.Cu" "B.Cu")
		(net "GND")
	)
	(via
		(at 335.255362 -268.569694)
		(size 0.4318)
		(drill 0.2032)
		(layers "F.Cu" "B.Cu")
		(net "GND")
	)
	(via
		(at 372.571518 -409.396184)
		(size 0.4572)
		(drill 0.254)
		(layers "F.Cu" "B.Cu")
		(net "GND")
	)
	(via
		(at 385.424934 -223.575626)
		(size 0.4572)
		(drill 0.2032)
		(layers "F.Cu" "B.Cu")
		(net "GND")
	)
	(via
		(at 334.205834 -242.294918)
		(size 0.4572)
		(drill 0.2032)
		(layers "F.Cu" "B.Cu")
		(net "GND")
	)
	(via
		(at 300.238414 -223.666558)
		(size 0.4572)
		(drill 0.2032)
		(layers "F.Cu" "B.Cu")
		(net "GND")
	)
	(via
		(at 182.549546 -246.616728)
		(size 0.4572)
		(drill 0.2032)
		(layers "F.Cu" "B.Cu")
		(net "GND")
	)
	(via
		(at 264.729214 -214.316564)
		(size 0.4572)
		(drill 0.2032)
		(layers "F.Cu" "B.Cu")
		(net "GND")
	)
	(via
		(at 311.882282 -314.616592)
		(size 0.4572)
		(drill 0.2032)
		(layers "F.Cu" "B.Cu")
		(net "GND")
	)
	(via
		(at 157.708346 -229.616762)
		(size 0.4572)
		(drill 0.2032)
		(layers "F.Cu" "B.Cu")
		(net "GND")
	)
	(via
		(at 434.589682 -233.86669)
		(size 0.4572)
		(drill 0.2032)
		(layers "F.Cu" "B.Cu")
		(net "GND")
	)
	(via
		(at 10.538968 -73.821798)
		(size 0.508)
		(drill 0.254)
		(layers "F.Cu" "B.Cu")
		(net "GND")
	)
	(via
		(at 115.869212 -230.086662)
		(size 0.4572)
		(drill 0.2032)
		(layers "F.Cu" "B.Cu")
		(net "GND")
	)
	(via
		(at 251.16409 -47.102522)
		(size 0.508)
		(drill 0.254)
		(layers "F.Cu" "B.Cu")
		(net "GND")
	)
	(via
		(at 233.496866 -117.155976)
		(size 0.508)
		(drill 0.254)
		(layers "F.Cu" "B.Cu")
		(net "GND")
	)
	(via
		(at 259.075682 -308.666642)
		(size 0.4572)
		(drill 0.2032)
		(layers "F.Cu" "B.Cu")
		(net "GND")
	)
	(via
		(at 11.135614 -291.666676)
		(size 0.4572)
		(drill 0.2032)
		(layers "F.Cu" "B.Cu")
		(net "GND")
	)
	(via
		(at 362.399834 -222.761556)
		(size 0.4572)
		(drill 0.2032)
		(layers "F.Cu" "B.Cu")
		(net "GND")
	)
	(via
		(at 187.883546 -242.3668)
		(size 0.4572)
		(drill 0.2032)
		(layers "F.Cu" "B.Cu")
		(net "GND")
	)
	(via
		(at 398.69745 -407.00452)
		(size 0.4064)
		(drill 0.2032)
		(layers "F.Cu" "B.Cu")
		(net "GND")
	)
	(via
		(at 417.292282 -282.316682)
		(size 0.4572)
		(drill 0.2032)
		(layers "F.Cu" "B.Cu")
		(net "GND")
	)
	(via
		(at 37.965888 -127.71374)
		(size 0.508)
		(drill 0.254)
		(layers "F.Cu" "B.Cu")
		(net "GND")
	)
	(via
		(at 193.598292 -32.177736)
		(size 0.508)
		(drill 0.254)
		(layers "F.Cu" "B.Cu")
		(net "GND")
	)
	(via
		(at 141.968982 -337.550252)
		(size 0.508)
		(drill 0.254)
		(layers "F.Cu" "B.Cu")
		(net "GND")
	)
	(via
		(at 13.345414 -239.81664)
		(size 0.4572)
		(drill 0.2032)
		(layers "F.Cu" "B.Cu")
		(net "GND")
	)
	(via
		(at 197.637146 -307.816758)
		(size 0.4572)
		(drill 0.2032)
		(layers "F.Cu" "B.Cu")
		(net "GND")
	)
	(via
		(at 279.816814 -208.366614)
		(size 0.4572)
		(drill 0.2032)
		(layers "F.Cu" "B.Cu")
		(net "GND")
	)
	(via
		(at 408.373072 -0.76454)
		(size 0.508)
		(drill 0.254)
		(layers "F.Cu" "B.Cu")
		(net "GND")
	)
	(via
		(at 296.794682 -297.616626)
		(size 0.4572)
		(drill 0.2032)
		(layers "F.Cu" "B.Cu")
		(net "GND")
	)
	(via
		(at 140.628878 -49.240948)
		(size 0.508)
		(drill 0.254)
		(layers "F.Cu" "B.Cu")
		(net "GND")
	)
	(via
		(at 201.737214 -221.116652)
		(size 0.4572)
		(drill 0.2032)
		(layers "F.Cu" "B.Cu")
		(net "GND")
	)
	(via
		(at 342.06688 -21.059648)
		(size 0.508)
		(drill 0.254)
		(layers "F.Cu" "B.Cu")
		(net "GND")
	)
	(via
		(at 287.360614 -225.36658)
		(size 0.4572)
		(drill 0.2032)
		(layers "F.Cu" "B.Cu")
		(net "GND")
	)
	(via
		(at 306.548282 -294.216582)
		(size 0.4572)
		(drill 0.2032)
		(layers "F.Cu" "B.Cu")
		(net "GND")
	)
	(via
		(at 333.375508 -275.08073)
		(size 0.4572)
		(drill 0.2032)
		(layers "F.Cu" "B.Cu")
		(net "GND")
	)
	(via
		(at 197.637146 -221.96679)
		(size 0.4572)
		(drill 0.2032)
		(layers "F.Cu" "B.Cu")
		(net "GND")
	)
	(via
		(at 442.133482 -232.166668)
		(size 0.4572)
		(drill 0.2032)
		(layers "F.Cu" "B.Cu")
		(net "GND")
	)
	(via
		(at 368.978434 -216.25052)
		(size 0.4572)
		(drill 0.2032)
		(layers "F.Cu" "B.Cu")
		(net "GND")
	)
	(via
		(at 445.577214 -260.21665)
		(size 0.4572)
		(drill 0.2032)
		(layers "F.Cu" "B.Cu")
		(net "GND")
	)
	(via
		(at 179.105814 -310.366664)
		(size 0.4572)
		(drill 0.2032)
		(layers "F.Cu" "B.Cu")
		(net "GND")
	)
	(via
		(at 29.666946 -236.416596)
		(size 0.4572)
		(drill 0.2032)
		(layers "F.Cu" "B.Cu")
		(net "GND")
	)
	(via
		(at 56.398414 -269.566644)
		(size 0.4572)
		(drill 0.2032)
		(layers "F.Cu" "B.Cu")
		(net "GND")
	)
	(via
		(at 54.508146 -301.866808)
		(size 0.4572)
		(drill 0.2032)
		(layers "F.Cu" "B.Cu")
		(net "GND")
	)
	(via
		(at 395.731238 -400.224244)
		(size 0.4572)
		(drill 0.254)
		(layers "F.Cu" "B.Cu")
		(net "GND")
	)
	(via
		(at 197.637146 -276.366732)
		(size 0.4572)
		(drill 0.2032)
		(layers "F.Cu" "B.Cu")
		(net "GND")
	)
	(via
		(at 80.25003 -426.69968)
		(size 0.4572)
		(drill 0.2032)
		(layers "F.Cu" "B.Cu")
		(net "GND")
	)
	(via
		(at 405.648414 -273.816572)
		(size 0.4572)
		(drill 0.2032)
		(layers "F.Cu" "B.Cu")
		(net "GND")
	)
	(via
		(at 19.38909 -19.770344)
		(size 0.508)
		(drill 0.254)
		(layers "F.Cu" "B.Cu")
		(net "GND")
	)
	(via
		(at 336.55508 -249.620024)
		(size 0.4572)
		(drill 0.2032)
		(layers "F.Cu" "B.Cu")
		(net "GND")
	)
	(via
		(at 121.577354 -403.883876)
		(size 0.4064)
		(drill 0.2032)
		(layers "F.Cu" "B.Cu")
		(net "GND")
	)
	(via
		(at 254.975614 -242.3668)
		(size 0.4572)
		(drill 0.2032)
		(layers "F.Cu" "B.Cu")
		(net "GND")
	)
	(via
		(at 374.147334 -243.108988)
		(size 0.4572)
		(drill 0.2032)
		(layers "F.Cu" "B.Cu")
		(net "GND")
	)
	(via
		(at 292.694614 -265.316716)
		(size 0.4572)
		(drill 0.2032)
		(layers "F.Cu" "B.Cu")
		(net "GND")
	)
	(via
		(at 344.061288 -335.704434)
		(size 0.49022)
		(drill 0.254)
		(layers "F.Cu" "B.Cu")
		(net "GND")
	)
	(via
		(at 407.858214 -306.116736)
		(size 0.4572)
		(drill 0.2032)
		(layers "F.Cu" "B.Cu")
		(net "GND")
	)
	(via
		(at 97.017078 -333.355188)
		(size 0.49022)
		(drill 0.254)
		(layers "F.Cu" "B.Cu")
		(net "GND")
	)
	(via
		(at 44.754546 -263.616694)
		(size 0.4572)
		(drill 0.2032)
		(layers "F.Cu" "B.Cu")
		(net "GND")
	)
	(via
		(at 310.207914 -276.366732)
		(size 0.4572)
		(drill 0.2032)
		(layers "F.Cu" "B.Cu")
		(net "GND")
	)
	(via
		(at 121.47296 -14.20749)
		(size 0.508)
		(drill 0.254)
		(layers "F.Cu" "B.Cu")
		(net "GND")
	)
	(via
		(at 157.708346 -260.21665)
		(size 0.4572)
		(drill 0.2032)
		(layers "F.Cu" "B.Cu")
		(net "GND")
	)
	(via
		(at 202.971146 -251.716794)
		(size 0.4572)
		(drill 0.2032)
		(layers "F.Cu" "B.Cu")
		(net "GND")
	)
	(via
		(at 385.708652 -340.977728)
		(size 0.49022)
		(drill 0.254)
		(layers "F.Cu" "B.Cu")
		(net "GND")
	)
	(via
		(at 66.152014 -233.86669)
		(size 0.4572)
		(drill 0.2032)
		(layers "F.Cu" "B.Cu")
		(net "GND")
	)
	(via
		(at 18.679414 -288.266632)
		(size 0.4572)
		(drill 0.2032)
		(layers "F.Cu" "B.Cu")
		(net "GND")
	)
	(via
		(at 104.231948 -279.964134)
		(size 0.4572)
		(drill 0.2032)
		(layers "F.Cu" "B.Cu")
		(net "GND")
	)
	(via
		(at 207.809084 -323.434456)
		(size 0.4572)
		(drill 0.2032)
		(layers "F.Cu" "B.Cu")
		(net "GND")
	)
	(via
		(at 24.332946 -220.266768)
		(size 0.4572)
		(drill 0.2032)
		(layers "F.Cu" "B.Cu")
		(net "GND")
	)
	(via
		(at 107.520994 -266.128246)
		(size 0.4572)
		(drill 0.2032)
		(layers "F.Cu" "B.Cu")
		(net "GND")
	)
	(via
		(at 106.230166 -235.431584)
		(size 0.4572)
		(drill 0.2032)
		(layers "F.Cu" "B.Cu")
		(net "GND")
	)
	(via
		(at 159.918146 -267.016738)
		(size 0.4572)
		(drill 0.2032)
		(layers "F.Cu" "B.Cu")
		(net "GND")
	)
	(via
		(at 138.534394 -267.755878)
		(size 0.4572)
		(drill 0.2032)
		(layers "F.Cu" "B.Cu")
		(net "GND")
	)
	(via
		(at 118.216934 -107.931712)
		(size 0.508)
		(drill 0.254)
		(layers "F.Cu" "B.Cu")
		(net "GND")
	)
	(via
		(at 268.829282 -266.1666)
		(size 0.4572)
		(drill 0.2032)
		(layers "F.Cu" "B.Cu")
		(net "GND")
	)
	(via
		(at 105.061766 -229.272846)
		(size 0.4572)
		(drill 0.2032)
		(layers "F.Cu" "B.Cu")
		(net "GND")
	)
	(via
		(at 191.983614 -303.566576)
		(size 0.4572)
		(drill 0.2032)
		(layers "F.Cu" "B.Cu")
		(net "GND")
	)
	(via
		(at 64.718438 -400.858228)
		(size 0.4064)
		(drill 0.2032)
		(layers "F.Cu" "B.Cu")
		(net "GND")
	)
	(via
		(at 380.835662 -287.28924)
		(size 0.4572)
		(drill 0.2032)
		(layers "F.Cu" "B.Cu")
		(net "GND")
	)
	(via
		(at 93.456506 -331.703426)
		(size 0.508)
		(drill 0.254)
		(layers "F.Cu" "B.Cu")
		(net "GND")
	)
	(via
		(at 445.577214 -242.3668)
		(size 0.4572)
		(drill 0.2032)
		(layers "F.Cu" "B.Cu")
		(net "GND")
	)
	(via
		(at 95.303594 -257.98907)
		(size 0.4572)
		(drill 0.2032)
		(layers "F.Cu" "B.Cu")
		(net "GND")
	)
	(via
		(at 157.708346 -261.916672)
		(size 0.4572)
		(drill 0.2032)
		(layers "F.Cu" "B.Cu")
		(net "GND")
	)
	(via
		(at 134.349998 -431.451258)
		(size 0.4572)
		(drill 0.2032)
		(layers "F.Cu" "B.Cu")
		(net "GND")
	)
	(via
		(at 165.252146 -270.416782)
		(size 0.4572)
		(drill 0.2032)
		(layers "F.Cu" "B.Cu")
		(net "GND")
	)
	(via
		(at 343.243662 -287.28924)
		(size 0.4572)
		(drill 0.2032)
		(layers "F.Cu" "B.Cu")
		(net "GND")
	)
	(via
		(at 39.420546 -260.21665)
		(size 0.4572)
		(drill 0.2032)
		(layers "F.Cu" "B.Cu")
		(net "GND")
	)
	(via
		(at 135.245094 -260.430772)
		(size 0.4572)
		(drill 0.2032)
		(layers "F.Cu" "B.Cu")
		(net "GND")
	)
	(via
		(at 167.461946 -242.3668)
		(size 0.4572)
		(drill 0.2032)
		(layers "F.Cu" "B.Cu")
		(net "GND")
	)
	(via
		(at 52.911248 -146.96567)
		(size 0.49022)
		(drill 0.254)
		(layers "F.Cu" "B.Cu")
		(net "GND")
	)
	(via
		(at 363.656118 -361.72775)
		(size 0.508)
		(drill 0.254)
		(layers "F.Cu" "B.Cu")
		(net "GND")
	)
	(via
		(at 372.607332 -62.216792)
		(size 0.508)
		(drill 0.254)
		(layers "F.Cu" "B.Cu")
		(net "GND")
	)
	(via
		(at 87.785194 -256.361438)
		(size 0.4572)
		(drill 0.2032)
		(layers "F.Cu" "B.Cu")
		(net "GND")
	)
	(via
		(at 389.268208 -338.964016)
		(size 0.508)
		(drill 0.254)
		(layers "F.Cu" "B.Cu")
		(net "GND")
	)
	(via
		(at 309.992014 -227.066602)
		(size 0.4572)
		(drill 0.2032)
		(layers "F.Cu" "B.Cu")
		(net "GND")
	)
	(via
		(at 462.555082 -299.316648)
		(size 0.4572)
		(drill 0.2032)
		(layers "F.Cu" "B.Cu")
		(net "GND")
	)
	(via
		(at 124.34697 -330.42352)
		(size 0.508)
		(drill 0.254)
		(layers "F.Cu" "B.Cu")
		(net "GND")
	)
	(via
		(at 289.250882 -303.566576)
		(size 0.4572)
		(drill 0.2032)
		(layers "F.Cu" "B.Cu")
		(net "GND")
	)
	(via
		(at 338.099908 -44.849796)
		(size 0.4572)
		(drill 0.2032)
		(layers "F.Cu" "B.Cu")
		(net "GND")
	)
	(via
		(at 348.470474 -170.936412)
		(size 0.508)
		(drill 0.254)
		(layers "F.Cu" "B.Cu")
		(net "GND")
	)
	(via
		(at 205.180946 -261.916672)
		(size 0.4572)
		(drill 0.2032)
		(layers "F.Cu" "B.Cu")
		(net "GND")
	)
	(via
		(at 98.483166 -242.294918)
		(size 0.4572)
		(drill 0.2032)
		(layers "F.Cu" "B.Cu")
		(net "GND")
	)
	(via
		(at 59.3852 -41.323768)
		(size 0.508)
		(drill 0.254)
		(layers "F.Cu" "B.Cu")
		(net "GND")
	)
	(via
		(at 338.544916 -287.28924)
		(size 0.4572)
		(drill 0.2032)
		(layers "F.Cu" "B.Cu")
		(net "GND")
	)
	(via
		(at 404.82393 -407.00452)
		(size 0.4064)
		(drill 0.2032)
		(layers "F.Cu" "B.Cu")
		(net "GND")
	)
	(via
		(at 63.250064 -425.547282)
		(size 0.4572)
		(drill 0.2032)
		(layers "F.Cu" "B.Cu")
		(net "GND")
	)
	(via
		(at 96.966278 -331.776832)
		(size 0.49022)
		(drill 0.254)
		(layers "F.Cu" "B.Cu")
		(net "GND")
	)
	(via
		(at 179.105814 -308.666642)
		(size 0.4572)
		(drill 0.2032)
		(layers "F.Cu" "B.Cu")
		(net "GND")
	)
	(via
		(at 46.964346 -272.116804)
		(size 0.4572)
		(drill 0.2032)
		(layers "F.Cu" "B.Cu")
		(net "GND")
	)
	(via
		(at 348.772734 -217.064336)
		(size 0.4572)
		(drill 0.2032)
		(layers "F.Cu" "B.Cu")
		(net "GND")
	)
	(via
		(at 257.185414 -248.31675)
		(size 0.4572)
		(drill 0.2032)
		(layers "F.Cu" "B.Cu")
		(net "GND")
	)
	(via
		(at 433.166774 -9.424924)
		(size 0.508)
		(drill 0.254)
		(layers "F.Cu" "B.Cu")
		(net "GND")
	)
	(via
		(at 123.387866 -223.575626)
		(size 0.4572)
		(drill 0.2032)
		(layers "F.Cu" "B.Cu")
		(net "GND")
	)
	(via
		(at 186.649614 -288.266632)
		(size 0.4572)
		(drill 0.2032)
		(layers "F.Cu" "B.Cu")
		(net "GND")
	)
	(via
		(at 307.782214 -242.3668)
		(size 0.4572)
		(drill 0.2032)
		(layers "F.Cu" "B.Cu")
		(net "GND")
	)
	(via
		(at 87.785194 -264.50036)
		(size 0.4572)
		(drill 0.2032)
		(layers "F.Cu" "B.Cu")
		(net "GND")
	)
	(via
		(at 99.532948 -275.08073)
		(size 0.4572)
		(drill 0.2032)
		(layers "F.Cu" "B.Cu")
		(net "GND")
	)
	(via
		(at 352.641662 -284.033722)
		(size 0.4572)
		(drill 0.2032)
		(layers "F.Cu" "B.Cu")
		(net "GND")
	)
	(via
		(at 214.155782 -93.004132)
		(size 0.508)
		(drill 0.254)
		(layers "F.Cu" "B.Cu")
		(net "GND")
	)
	(via
		(at 338.904834 -222.761556)
		(size 0.4572)
		(drill 0.2032)
		(layers "F.Cu" "B.Cu")
		(net "GND")
	)
	(via
		(at 159.918146 -268.71676)
		(size 0.4572)
		(drill 0.2032)
		(layers "F.Cu" "B.Cu")
		(net "GND")
	)
	(via
		(at 383.185162 -255.547622)
		(size 0.4572)
		(drill 0.2032)
		(layers "F.Cu" "B.Cu")
		(net "GND")
	)
	(via
		(at 13.345414 -305.266598)
		(size 0.4572)
		(drill 0.2032)
		(layers "F.Cu" "B.Cu")
		(net "GND")
	)
	(via
		(at 319.047622 -36.439348)
		(size 0.508)
		(drill 0.254)
		(layers "F.Cu" "B.Cu")
		(net "GND")
	)
	(via
		(at 375.5644 -353.828858)
		(size 0.508)
		(drill 0.254)
		(layers "F.Cu" "B.Cu")
		(net "GND")
	)
	(via
		(at 370.967762 -253.919736)
		(size 0.4572)
		(drill 0.2032)
		(layers "F.Cu" "B.Cu")
		(net "GND")
	)
	(via
		(at 97.543366 -216.25052)
		(size 0.4572)
		(drill 0.2032)
		(layers "F.Cu" "B.Cu")
		(net "GND")
	)
	(via
		(at 116.068094 -396.163038)
		(size 0.508)
		(drill 0.254)
		(layers "F.Cu" "B.Cu")
		(net "GND")
	)
	(via
		(at 126.098554 -333.13243)
		(size 0.508)
		(drill 0.254)
		(layers "F.Cu" "B.Cu")
		(net "GND")
	)
	(via
		(at 51.573176 -173.745144)
		(size 0.49022)
		(drill 0.254)
		(layers "F.Cu" "B.Cu")
		(net "GND")
	)
	(via
		(at 127.907288 -359.419906)
		(size 0.508)
		(drill 0.254)
		(layers "F.Cu" "B.Cu")
		(net "GND")
	)
	(via
		(at 315.250068 -435.0512)
		(size 0.4572)
		(drill 0.2032)
		(layers "F.Cu" "B.Cu")
		(net "GND")
	)
	(via
		(at 25.992836 -127.159512)
		(size 0.508)
		(drill 0.254)
		(layers "F.Cu" "B.Cu")
		(net "GND")
	)
	(via
		(at 102.821994 -271.011396)
		(size 0.4572)
		(drill 0.2032)
		(layers "F.Cu" "B.Cu")
		(net "GND")
	)
	(via
		(at 113.629694 -266.941808)
		(size 0.4572)
		(drill 0.2032)
		(layers "F.Cu" "B.Cu")
		(net "GND")
	)
	(via
		(at 306.764182 -272.966688)
		(size 0.4572)
		(drill 0.2032)
		(layers "F.Cu" "B.Cu")
		(net "GND")
	)
	(via
		(at 188.38418 -357.04145)
		(size 0.508)
		(drill 0.254)
		(layers "F.Cu" "B.Cu")
		(net "GND")
	)
	(via
		(at 96.243394 -277.522432)
		(size 0.4572)
		(drill 0.2032)
		(layers "F.Cu" "B.Cu")
		(net "GND")
	)
	(via
		(at 83.54441 -338.964016)
		(size 0.508)
		(drill 0.254)
		(layers "F.Cu" "B.Cu")
		(net "GND")
	)
	(via
		(at 98.483166 -216.25052)
		(size 0.4572)
		(drill 0.2032)
		(layers "F.Cu" "B.Cu")
		(net "GND")
	)
	(via
		(at 450.911214 -278.066754)
		(size 0.4572)
		(drill 0.2032)
		(layers "F.Cu" "B.Cu")
		(net "GND")
	)
	(via
		(at 306.5526 -29.4386)
		(size 0.508)
		(drill 0.254)
		(layers "F.Cu" "B.Cu")
		(net "GND")
	)
	(via
		(at 126.316994 -287.28924)
		(size 0.4572)
		(drill 0.2032)
		(layers "F.Cu" "B.Cu")
		(net "GND")
	)
	(via
		(at 430.489614 -272.116804)
		(size 0.4572)
		(drill 0.2032)
		(layers "F.Cu" "B.Cu")
		(net "GND")
	)
	(via
		(at 372.26748 -233.34218)
		(size 0.4572)
		(drill 0.2032)
		(layers "F.Cu" "B.Cu")
		(net "GND")
	)
	(via
		(at 314.092082 -280.61666)
		(size 0.4572)
		(drill 0.2032)
		(layers "F.Cu" "B.Cu")
		(net "GND")
	)
	(via
		(at 216.824814 -294.216582)
		(size 0.4572)
		(drill 0.2032)
		(layers "F.Cu" "B.Cu")
		(net "GND")
	)
	(via
		(at 442.133482 -245.76659)
		(size 0.4572)
		(drill 0.2032)
		(layers "F.Cu" "B.Cu")
		(net "GND")
	)
	(via
		(at 264.729214 -296.766742)
		(size 0.4572)
		(drill 0.2032)
		(layers "F.Cu" "B.Cu")
		(net "GND")
	)
	(via
		(at 339.014816 -258.80314)
		(size 0.4572)
		(drill 0.2032)
		(layers "F.Cu" "B.Cu")
		(net "GND")
	)
	(via
		(at 171.790614 -272.966688)
		(size 0.4572)
		(drill 0.2032)
		(layers "F.Cu" "B.Cu")
		(net "GND")
	)
	(via
		(at 305.779932 -47.104554)
		(size 0.508)
		(drill 0.254)
		(layers "F.Cu" "B.Cu")
		(net "GND")
	)
	(via
		(at 400.24685 -10.16508)
		(size 0.508)
		(drill 0.254)
		(layers "F.Cu" "B.Cu")
		(net "GND")
	)
	(via
		(at 285.150814 -289.11677)
		(size 0.4572)
		(drill 0.2032)
		(layers "F.Cu" "B.Cu")
		(net "GND")
	)
	(via
		(at 450.911214 -201.56678)
		(size 0.4572)
		(drill 0.2032)
		(layers "F.Cu" "B.Cu")
		(net "GND")
	)
	(via
		(at 420.736014 -309.51678)
		(size 0.4572)
		(drill 0.2032)
		(layers "F.Cu" "B.Cu")
		(net "GND")
	)
	(via
		(at 464.509358 -39.75608)
		(size 0.508)
		(drill 0.254)
		(layers "F.Cu" "B.Cu")
		(net "GND")
	)
	(via
		(at 88.615012 -230.086662)
		(size 0.4572)
		(drill 0.2032)
		(layers "F.Cu" "B.Cu")
		(net "GND")
	)
	(via
		(at 171.562014 -213.46668)
		(size 0.4572)
		(drill 0.2032)
		(layers "F.Cu" "B.Cu")
		(net "GND")
	)
	(via
		(at 129.383028 -342.270334)
		(size 0.508)
		(drill 0.254)
		(layers "F.Cu" "B.Cu")
		(net "GND")
	)
	(via
		(at 376.496834 -226.017328)
		(size 0.4572)
		(drill 0.2032)
		(layers "F.Cu" "B.Cu")
		(net "GND")
	)
	(via
		(at 44.095924 -6.597396)
		(size 0.508)
		(drill 0.254)
		(layers "F.Cu" "B.Cu")
		(net "GND")
	)
	(via
		(at 378.610622 -404.51786)
		(size 0.4572)
		(drill 0.254)
		(layers "F.Cu" "B.Cu")
		(net "GND")
	)
	(via
		(at 346.570808 -407.00452)
		(size 0.4064)
		(drill 0.2032)
		(layers "F.Cu" "B.Cu")
		(net "GND")
	)
	(via
		(at 120.678194 -269.38351)
		(size 0.4572)
		(drill 0.2032)
		(layers "F.Cu" "B.Cu")
		(net "GND")
	)
	(via
		(at 132.425694 -286.475424)
		(size 0.4572)
		(drill 0.2032)
		(layers "F.Cu" "B.Cu")
		(net "GND")
	)
	(via
		(at 139.944094 -262.058658)
		(size 0.4572)
		(drill 0.2032)
		(layers "F.Cu" "B.Cu")
		(net "GND")
	)
	(via
		(at 348.772734 -241.481102)
		(size 0.4572)
		(drill 0.2032)
		(layers "F.Cu" "B.Cu")
		(net "GND")
	)
	(via
		(at 117.22608 -123.148598)
		(size 0.508)
		(drill 0.254)
		(layers "F.Cu" "B.Cu")
		(net "GND")
	)
	(via
		(at 86.265766 -248.806208)
		(size 0.4572)
		(drill 0.2032)
		(layers "F.Cu" "B.Cu")
		(net "GND")
	)
	(via
		(at 340.894416 -253.919736)
		(size 0.4572)
		(drill 0.2032)
		(layers "F.Cu" "B.Cu")
		(net "GND")
	)
	(via
		(at 420.736014 -281.466798)
		(size 0.4572)
		(drill 0.2032)
		(layers "F.Cu" "B.Cu")
		(net "GND")
	)
	(via
		(at 384.125216 -275.080984)
		(size 0.4318)
		(drill 0.2032)
		(layers "F.Cu" "B.Cu")
		(net "GND")
	)
	(via
		(at 39.420546 -300.166786)
		(size 0.4572)
		(drill 0.2032)
		(layers "F.Cu" "B.Cu")
		(net "GND")
	)
	(via
		(at 300.663864 -360.840274)
		(size 0.49022)
		(drill 0.254)
		(layers "F.Cu" "B.Cu")
		(net "GND")
	)
	(via
		(at 329.25004 -438.499758)
		(size 0.4572)
		(drill 0.2032)
		(layers "F.Cu" "B.Cu")
		(net "GND")
	)
	(via
		(at 9.963404 -100.417884)
		(size 0.508)
		(drill 0.254)
		(layers "F.Cu" "B.Cu")
		(net "GND")
	)
	(via
		(at 86.265766 -227.64496)
		(size 0.4572)
		(drill 0.2032)
		(layers "F.Cu" "B.Cu")
		(net "GND")
	)
	(via
		(at 37.210746 -311.216802)
		(size 0.4572)
		(drill 0.2032)
		(layers "F.Cu" "B.Cu")
		(net "GND")
	)
	(via
		(at 373.317262 -287.28924)
		(size 0.4572)
		(drill 0.2032)
		(layers "F.Cu" "B.Cu")
		(net "GND")
	)
	(via
		(at 422.945814 -204.96657)
		(size 0.4572)
		(drill 0.2032)
		(layers "F.Cu" "B.Cu")
		(net "GND")
	)
	(via
		(at 48.854614 -202.416664)
		(size 0.4572)
		(drill 0.2032)
		(layers "F.Cu" "B.Cu")
		(net "GND")
	)
	(via
		(at 147.429474 -407.00452)
		(size 0.4064)
		(drill 0.2032)
		(layers "F.Cu" "B.Cu")
		(net "GND")
	)
	(via
		(at 442.133482 -241.516662)
		(size 0.4572)
		(drill 0.2032)
		(layers "F.Cu" "B.Cu")
		(net "GND")
	)
	(via
		(at 319.25006 -425.547282)
		(size 0.4572)
		(drill 0.2032)
		(layers "F.Cu" "B.Cu")
		(net "GND")
	)
	(via
		(at 134.349998 -433.899564)
		(size 0.4572)
		(drill 0.2032)
		(layers "F.Cu" "B.Cu")
		(net "GND")
	)
	(via
		(at 195.427346 -313.766708)
		(size 0.4572)
		(drill 0.2032)
		(layers "F.Cu" "B.Cu")
		(net "GND")
	)
	(via
		(at 105.641394 -284.033722)
		(size 0.4572)
		(drill 0.2032)
		(layers "F.Cu" "B.Cu")
		(net "GND")
	)
	(via
		(at 430.489614 -195.616576)
		(size 0.4572)
		(drill 0.2032)
		(layers "F.Cu" "B.Cu")
		(net "GND")
	)
	(via
		(at 163.827714 -410.030168)
		(size 0.4064)
		(drill 0.2032)
		(layers "F.Cu" "B.Cu")
		(net "GND")
	)
	(via
		(at 195.427346 -287.416748)
		(size 0.4572)
		(drill 0.2032)
		(layers "F.Cu" "B.Cu")
		(net "GND")
	)
	(via
		(at 432.076098 -182.63997)
		(size 0.508)
		(drill 0.254)
		(layers "F.Cu" "B.Cu")
		(net "GND")
	)
	(via
		(at 74.816462 -39.070026)
		(size 0.508)
		(drill 0.254)
		(layers "F.Cu" "B.Cu")
		(net "GND")
	)
	(via
		(at 211.102956 -29.266642)
		(size 0.508)
		(drill 0.254)
		(layers "F.Cu" "B.Cu")
		(net "GND")
	)
	(via
		(at 164.018214 -269.566644)
		(size 0.4572)
		(drill 0.2032)
		(layers "F.Cu" "B.Cu")
		(net "GND")
	)
	(via
		(at 92.954348 -265.314176)
		(size 0.4572)
		(drill 0.2032)
		(layers "F.Cu" "B.Cu")
		(net "GND")
	)
	(via
		(at 358.425496 -339.324696)
		(size 0.508)
		(drill 0.254)
		(layers "F.Cu" "B.Cu")
		(net "GND")
	)
	(via
		(at 87.301578 -277.244302)
		(size 0.4572)
		(drill 0.2032)
		(layers "F.Cu" "B.Cu")
		(net "GND")
	)
	(via
		(at 402.293328 -6.586474)
		(size 0.508)
		(drill 0.254)
		(layers "F.Cu" "B.Cu")
		(net "GND")
	)
	(via
		(at 93.369638 -403.883876)
		(size 0.4064)
		(drill 0.2032)
		(layers "F.Cu" "B.Cu")
		(net "GND")
	)
	(via
		(at 372.377462 -266.128246)
		(size 0.4572)
		(drill 0.2032)
		(layers "F.Cu" "B.Cu")
		(net "GND")
	)
	(via
		(at 409.519882 -272.966688)
		(size 0.4572)
		(drill 0.2032)
		(layers "F.Cu" "B.Cu")
		(net "GND")
	)
	(via
		(at 172.795946 -221.96679)
		(size 0.4572)
		(drill 0.2032)
		(layers "F.Cu" "B.Cu")
		(net "GND")
	)
	(via
		(at 464.764882 -221.116652)
		(size 0.4572)
		(drill 0.2032)
		(layers "F.Cu" "B.Cu")
		(net "GND")
	)
	(via
		(at 77.227938 -347.61551)
		(size 0.508)
		(drill 0.254)
		(layers "F.Cu" "B.Cu")
		(net "GND")
	)
	(via
		(at 375.667016 -258.80314)
		(size 0.4572)
		(drill 0.2032)
		(layers "F.Cu" "B.Cu")
		(net "GND")
	)
	(via
		(at 346.533216 -279.964134)
		(size 0.4572)
		(drill 0.2032)
		(layers "F.Cu" "B.Cu")
		(net "GND")
	)
	(via
		(at 358.640634 -216.25052)
		(size 0.4572)
		(drill 0.2032)
		(layers "F.Cu" "B.Cu")
		(net "GND")
	)
	(via
		(at 291.460682 -207.51673)
		(size 0.4572)
		(drill 0.2032)
		(layers "F.Cu" "B.Cu")
		(net "GND")
	)
	(via
		(at 374.257062 -279.150318)
		(size 0.4572)
		(drill 0.2032)
		(layers "F.Cu" "B.Cu")
		(net "GND")
	)
	(via
		(at 97.073466 -213.732618)
		(size 0.4572)
		(drill 0.2032)
		(layers "F.Cu" "B.Cu")
		(net "GND")
	)
	(via
		(at 182.549546 -260.21665)
		(size 0.4572)
		(drill 0.2032)
		(layers "F.Cu" "B.Cu")
		(net "GND")
	)
	(via
		(at 424.836082 -269.566644)
		(size 0.4572)
		(drill 0.2032)
		(layers "F.Cu" "B.Cu")
		(net "GND")
	)
	(via
		(at 33.767014 -250.866656)
		(size 0.4572)
		(drill 0.2032)
		(layers "F.Cu" "B.Cu")
		(net "GND")
	)
	(via
		(at 270.063214 -307.816758)
		(size 0.4572)
		(drill 0.2032)
		(layers "F.Cu" "B.Cu")
		(net "GND")
	)
	(via
		(at 54.508146 -290.816792)
		(size 0.4572)
		(drill 0.2032)
		(layers "F.Cu" "B.Cu")
		(net "GND")
	)
	(via
		(at 54.3814 -172.307504)
		(size 0.508)
		(drill 0.254)
		(layers "F.Cu" "B.Cu")
		(net "GND")
	)
	(via
		(at 292.694614 -292.516814)
		(size 0.4572)
		(drill 0.2032)
		(layers "F.Cu" "B.Cu")
		(net "GND")
	)
	(via
		(at 424.12158 -147.450048)
		(size 0.508)
		(drill 0.254)
		(layers "F.Cu" "B.Cu")
		(net "GND")
	)
	(via
		(at 161.808414 -221.116652)
		(size 0.4572)
		(drill 0.2032)
		(layers "F.Cu" "B.Cu")
		(net "GND")
	)
	(via
		(at 63.942214 -314.616592)
		(size 0.4572)
		(drill 0.2032)
		(layers "F.Cu" "B.Cu")
		(net "GND")
	)
	(via
		(at 338.43468 -225.203258)
		(size 0.4572)
		(drill 0.2032)
		(layers "F.Cu" "B.Cu")
		(net "GND")
	)
	(via
		(at 422.945814 -279.766776)
		(size 0.4572)
		(drill 0.2032)
		(layers "F.Cu" "B.Cu")
		(net "GND")
	)
	(via
		(at 384.594862 -282.405836)
		(size 0.4572)
		(drill 0.2032)
		(layers "F.Cu" "B.Cu")
		(net "GND")
	)
	(via
		(at 380.725934 -233.34218)
		(size 0.4572)
		(drill 0.2032)
		(layers "F.Cu" "B.Cu")
		(net "GND")
	)
	(via
		(at 37.210746 -306.116736)
		(size 0.4572)
		(drill 0.2032)
		(layers "F.Cu" "B.Cu")
		(net "GND")
	)
	(via
		(at 382.715262 -287.28924)
		(size 0.4572)
		(drill 0.2032)
		(layers "F.Cu" "B.Cu")
		(net "GND")
	)
	(via
		(at 54.508146 -212.616796)
		(size 0.4572)
		(drill 0.2032)
		(layers "F.Cu" "B.Cu")
		(net "GND")
	)
	(via
		(at 299.004482 -194.766692)
		(size 0.4572)
		(drill 0.2032)
		(layers "F.Cu" "B.Cu")
		(net "GND")
	)
	(via
		(at 42.3291 -6.090412)
		(size 0.508)
		(drill 0.254)
		(layers "F.Cu" "B.Cu")
		(net "GND")
	)
	(via
		(at 420.736014 -206.666592)
		(size 0.4572)
		(drill 0.2032)
		(layers "F.Cu" "B.Cu")
		(net "GND")
	)
	(via
		(at 121.38787 -423.479468)
		(size 0.508)
		(drill 0.254)
		(layers "F.Cu" "B.Cu")
		(net "GND")
	)
	(via
		(at 7.035546 -281.466798)
		(size 0.4572)
		(drill 0.2032)
		(layers "F.Cu" "B.Cu")
		(net "GND")
	)
	(via
		(at 329.439778 -41.871646)
		(size 0.4572)
		(drill 0.2032)
		(layers "F.Cu" "B.Cu")
		(net "GND")
	)
	(via
		(at 49.290986 -162.280854)
		(size 0.508)
		(drill 0.254)
		(layers "F.Cu" "B.Cu")
		(net "GND")
	)
	(via
		(at 55.254906 -410.664152)
		(size 0.4572)
		(drill 0.254)
		(layers "F.Cu" "B.Cu")
		(net "GND")
	)
	(via
		(at 435.823614 -315.46673)
		(size 0.4572)
		(drill 0.2032)
		(layers "F.Cu" "B.Cu")
		(net "GND")
	)
	(via
		(at 360.05008 -234.970066)
		(size 0.4572)
		(drill 0.2032)
		(layers "F.Cu" "B.Cu")
		(net "GND")
	)
	(via
		(at 375.557034 -222.761556)
		(size 0.4572)
		(drill 0.2032)
		(layers "F.Cu" "B.Cu")
		(net "GND")
	)
	(via
		(at 196.912484 -323.434456)
		(size 0.4572)
		(drill 0.2032)
		(layers "F.Cu" "B.Cu")
		(net "GND")
	)
	(via
		(at 137.553954 -344.90533)
		(size 0.49022)
		(drill 0.254)
		(layers "F.Cu" "B.Cu")
		(net "GND")
	)
	(via
		(at 70.48373 -400.224244)
		(size 0.4572)
		(drill 0.254)
		(layers "F.Cu" "B.Cu")
		(net "GND")
	)
	(via
		(at 39.420546 -298.466764)
		(size 0.4572)
		(drill 0.2032)
		(layers "F.Cu" "B.Cu")
		(net "GND")
	)
	(via
		(at 45.392594 -5.596636)
		(size 0.508)
		(drill 0.254)
		(layers "F.Cu" "B.Cu")
		(net "GND")
	)
	(via
		(at 259.075682 -245.76659)
		(size 0.4572)
		(drill 0.2032)
		(layers "F.Cu" "B.Cu")
		(net "GND")
	)
	(via
		(at 287.360614 -292.516814)
		(size 0.4572)
		(drill 0.2032)
		(layers "F.Cu" "B.Cu")
		(net "GND")
	)
	(via
		(at 48.854614 -271.266666)
		(size 0.4572)
		(drill 0.2032)
		(layers "F.Cu" "B.Cu")
		(net "GND")
	)
	(via
		(at 423.14876 -384.266948)
		(size 0.508)
		(drill 0.254)
		(layers "F.Cu" "B.Cu")
		(net "GND")
	)
	(via
		(at 63.3222 -129.631948)
		(size 0.508)
		(drill 0.254)
		(layers "F.Cu" "B.Cu")
		(net "GND")
	)
	(via
		(at 309.526686 -12.544552)
		(size 0.508)
		(drill 0.254)
		(layers "F.Cu" "B.Cu")
		(net "GND")
	)
	(via
		(at 108.27893 -57.876948)
		(size 0.508)
		(drill 0.254)
		(layers "F.Cu" "B.Cu")
		(net "GND")
	)
	(via
		(at 180.339746 -298.466764)
		(size 0.4572)
		(drill 0.2032)
		(layers "F.Cu" "B.Cu")
		(net "GND")
	)
	(via
		(at 181.407562 -416.503104)
		(size 0.508)
		(drill 0.254)
		(layers "F.Cu" "B.Cu")
		(net "GND")
	)
	(via
		(at 217.6018 -77.434948)
		(size 0.508)
		(drill 0.254)
		(layers "F.Cu" "B.Cu")
		(net "GND")
	)
	(via
		(at 411.355286 -174.363126)
		(size 0.508)
		(drill 0.254)
		(layers "F.Cu" "B.Cu")
		(net "GND")
	)
	(via
		(at 194.193414 -291.666676)
		(size 0.4572)
		(drill 0.2032)
		(layers "F.Cu" "B.Cu")
		(net "GND")
	)
	(via
		(at 66.367914 -282.316682)
		(size 0.4572)
		(drill 0.2032)
		(layers "F.Cu" "B.Cu")
		(net "GND")
	)
	(via
		(at 176.896014 -275.516594)
		(size 0.4572)
		(drill 0.2032)
		(layers "F.Cu" "B.Cu")
		(net "GND")
	)
	(via
		(at 113.050066 -238.225838)
		(size 0.4572)
		(drill 0.2032)
		(layers "F.Cu" "B.Cu")
		(net "GND")
	)
	(via
		(at 33.767014 -196.466714)
		(size 0.4572)
		(drill 0.2032)
		(layers "F.Cu" "B.Cu")
		(net "GND")
	)
	(via
		(at 108.820966 -230.900478)
		(size 0.4572)
		(drill 0.2032)
		(layers "F.Cu" "B.Cu")
		(net "GND")
	)
	(via
		(at 264.729214 -307.816758)
		(size 0.4572)
		(drill 0.2032)
		(layers "F.Cu" "B.Cu")
		(net "GND")
	)
	(via
		(at 268.829282 -314.616592)
		(size 0.4572)
		(drill 0.2032)
		(layers "F.Cu" "B.Cu")
		(net "GND")
	)
	(via
		(at 207.071214 -244.066568)
		(size 0.4572)
		(drill 0.2032)
		(layers "F.Cu" "B.Cu")
		(net "GND")
	)
	(via
		(at 299.004482 -288.266632)
		(size 0.4572)
		(drill 0.2032)
		(layers "F.Cu" "B.Cu")
		(net "GND")
	)
	(via
		(at 366.269016 -268.569694)
		(size 0.4572)
		(drill 0.2032)
		(layers "F.Cu" "B.Cu")
		(net "GND")
	)
	(via
		(at 14.579346 -210.916774)
		(size 0.4572)
		(drill 0.2032)
		(layers "F.Cu" "B.Cu")
		(net "GND")
	)
	(via
		(at 413.349948 -436.051198)
		(size 0.4572)
		(drill 0.2032)
		(layers "F.Cu" "B.Cu")
		(net "GND")
	)
	(via
		(at 100.472748 -255.547622)
		(size 0.4572)
		(drill 0.2032)
		(layers "F.Cu" "B.Cu")
		(net "GND")
	)
	(via
		(at 16.789146 -296.766742)
		(size 0.4572)
		(drill 0.2032)
		(layers "F.Cu" "B.Cu")
		(net "GND")
	)
	(via
		(at 366.268762 -281.59202)
		(size 0.4572)
		(drill 0.2032)
		(layers "F.Cu" "B.Cu")
		(net "GND")
	)
	(via
		(at 353.581462 -284.033722)
		(size 0.4572)
		(drill 0.2032)
		(layers "F.Cu" "B.Cu")
		(net "GND")
	)
	(via
		(at 328.625708 -41.401746)
		(size 0.4572)
		(drill 0.2032)
		(layers "F.Cu" "B.Cu")
		(net "GND")
	)
	(via
		(at 197.637146 -227.066602)
		(size 0.4572)
		(drill 0.2032)
		(layers "F.Cu" "B.Cu")
		(net "GND")
	)
	(via
		(at 311.882282 -247.466612)
		(size 0.4572)
		(drill 0.2032)
		(layers "F.Cu" "B.Cu")
		(net "GND")
	)
	(via
		(at 46.964346 -206.666592)
		(size 0.4572)
		(drill 0.2032)
		(layers "F.Cu" "B.Cu")
		(net "GND")
	)
	(via
		(at 62.051946 -272.116804)
		(size 0.4572)
		(drill 0.2032)
		(layers "F.Cu" "B.Cu")
		(net "GND")
	)
	(via
		(at 261.285482 -204.116686)
		(size 0.4572)
		(drill 0.2032)
		(layers "F.Cu" "B.Cu")
		(net "GND")
	)
	(via
		(at 43.520614 -241.516662)
		(size 0.4572)
		(drill 0.2032)
		(layers "F.Cu" "B.Cu")
		(net "GND")
	)
	(via
		(at 133.725666 -244.73662)
		(size 0.4572)
		(drill 0.2032)
		(layers "F.Cu" "B.Cu")
		(net "GND")
	)
	(via
		(at 367.208562 -289.807142)
		(size 0.4572)
		(drill 0.2032)
		(layers "F.Cu" "B.Cu")
		(net "GND")
	)
	(via
		(at 186.649614 -230.466646)
		(size 0.4572)
		(drill 0.2032)
		(layers "F.Cu" "B.Cu")
		(net "GND")
	)
	(via
		(at 342.773762 -289.807142)
		(size 0.4572)
		(drill 0.2032)
		(layers "F.Cu" "B.Cu")
		(net "GND")
	)
	(via
		(at 264.729214 -225.36658)
		(size 0.4572)
		(drill 0.2032)
		(layers "F.Cu" "B.Cu")
		(net "GND")
	)
	(via
		(at 165.501066 -26.086562)
		(size 0.508)
		(drill 0.254)
		(layers "F.Cu" "B.Cu")
		(net "GND")
	)
	(via
		(at 190.093346 -220.266768)
		(size 0.4572)
		(drill 0.2032)
		(layers "F.Cu" "B.Cu")
		(net "GND")
	)
	(via
		(at 172.795946 -289.11677)
		(size 0.4572)
		(drill 0.2032)
		(layers "F.Cu" "B.Cu")
		(net "GND")
	)
	(via
		(at 199.527414 -221.116652)
		(size 0.4572)
		(drill 0.2032)
		(layers "F.Cu" "B.Cu")
		(net "GND")
	)
	(via
		(at 133.835648 -287.28924)
		(size 0.4572)
		(drill 0.2032)
		(layers "F.Cu" "B.Cu")
		(net "GND")
	)
	(via
		(at 74.89317 -410.664152)
		(size 0.4572)
		(drill 0.254)
		(layers "F.Cu" "B.Cu")
		(net "GND")
	)
	(via
		(at 332.697836 -409.396184)
		(size 0.4572)
		(drill 0.254)
		(layers "F.Cu" "B.Cu")
		(net "GND")
	)
	(via
		(at 234.523788 -251.517658)
		(size 0.508)
		(drill 0.254)
		(layers "F.Cu" "B.Cu")
		(net "GND")
	)
	(via
		(at 302.448214 -204.96657)
		(size 0.4572)
		(drill 0.2032)
		(layers "F.Cu" "B.Cu")
		(net "GND")
	)
	(via
		(at 159.918146 -231.316784)
		(size 0.4572)
		(drill 0.2032)
		(layers "F.Cu" "B.Cu")
		(net "GND")
	)
	(via
		(at 123.387612 -230.086662)
		(size 0.4572)
		(drill 0.2032)
		(layers "F.Cu" "B.Cu")
		(net "GND")
	)
	(via
		(at 375.196862 -284.033722)
		(size 0.4572)
		(drill 0.2032)
		(layers "F.Cu" "B.Cu")
		(net "GND")
	)
	(via
		(at 18.679414 -286.56661)
		(size 0.4572)
		(drill 0.2032)
		(layers "F.Cu" "B.Cu")
		(net "GND")
	)
	(via
		(at 415.402014 -272.116804)
		(size 0.4572)
		(drill 0.2032)
		(layers "F.Cu" "B.Cu")
		(net "GND")
	)
	(via
		(at 59.842146 -272.116804)
		(size 0.4572)
		(drill 0.2032)
		(layers "F.Cu" "B.Cu")
		(net "GND")
	)
	(via
		(at 439.12028 -7.153148)
		(size 0.508)
		(drill 0.254)
		(layers "F.Cu" "B.Cu")
		(net "GND")
	)
	(via
		(at 171.562014 -266.1666)
		(size 0.4572)
		(drill 0.2032)
		(layers "F.Cu" "B.Cu")
		(net "GND")
	)
	(via
		(at 471.03538 -64.104266)
		(size 0.508)
		(drill 0.254)
		(layers "F.Cu" "B.Cu")
		(net "GND")
	)
	(via
		(at 421.502332 -179.107846)
		(size 0.508)
		(drill 0.254)
		(layers "F.Cu" "B.Cu")
		(net "GND")
	)
	(via
		(at 175.90008 -38.730428)
		(size 0.508)
		(drill 0.254)
		(layers "F.Cu" "B.Cu")
		(net "GND")
	)
	(via
		(at 435.823614 -260.21665)
		(size 0.4572)
		(drill 0.2032)
		(layers "F.Cu" "B.Cu")
		(net "GND")
	)
	(via
		(at 382.245616 -271.825212)
		(size 0.4572)
		(drill 0.2032)
		(layers "F.Cu" "B.Cu")
		(net "GND")
	)
	(via
		(at 175.005746 -315.46673)
		(size 0.4572)
		(drill 0.2032)
		(layers "F.Cu" "B.Cu")
		(net "GND")
	)
	(via
		(at 261.285482 -221.116652)
		(size 0.4572)
		(drill 0.2032)
		(layers "F.Cu" "B.Cu")
		(net "GND")
	)
	(via
		(at 281.707082 -271.266666)
		(size 0.4572)
		(drill 0.2032)
		(layers "F.Cu" "B.Cu")
		(net "GND")
	)
	(via
		(at 309.992014 -216.016586)
		(size 0.4572)
		(drill 0.2032)
		(layers "F.Cu" "B.Cu")
		(net "GND")
	)
	(via
		(at 306.548282 -244.066568)
		(size 0.4572)
		(drill 0.2032)
		(layers "F.Cu" "B.Cu")
		(net "GND")
	)
	(via
		(at 336.530696 -337.692238)
		(size 0.49022)
		(drill 0.254)
		(layers "F.Cu" "B.Cu")
		(net "GND")
	)
	(via
		(at 34.386266 -19.13636)
		(size 0.508)
		(drill 0.254)
		(layers "F.Cu" "B.Cu")
		(net "GND")
	)
	(via
		(at 80.25003 -425.547282)
		(size 0.4572)
		(drill 0.2032)
		(layers "F.Cu" "B.Cu")
		(net "GND")
	)
	(via
		(at 24.332946 -206.666592)
		(size 0.4572)
		(drill 0.2032)
		(layers "F.Cu" "B.Cu")
		(net "GND")
	)
	(via
		(at 435.823614 -212.616796)
		(size 0.4572)
		(drill 0.2032)
		(layers "F.Cu" "B.Cu")
		(net "GND")
	)
	(via
		(at 309.992014 -204.96657)
		(size 0.4572)
		(drill 0.2032)
		(layers "F.Cu" "B.Cu")
		(net "GND")
	)
	(via
		(at 141.302994 -410.030168)
		(size 0.4064)
		(drill 0.2032)
		(layers "F.Cu" "B.Cu")
		(net "GND")
	)
	(via
		(at 63.956438 -25.614122)
		(size 0.508)
		(drill 0.254)
		(layers "F.Cu" "B.Cu")
		(net "GND")
	)
	(via
		(at 88.805766 -335.976214)
		(size 0.49022)
		(drill 0.254)
		(layers "F.Cu" "B.Cu")
		(net "GND")
	)
	(via
		(at 257.971798 -99.398836)
		(size 0.508)
		(drill 0.254)
		(layers "F.Cu" "B.Cu")
		(net "GND")
	)
	(via
		(at 112.75314 -395.122908)
		(size 0.508)
		(drill 0.254)
		(layers "F.Cu" "B.Cu")
		(net "GND")
	)
	(via
		(at 56.251856 -144.300702)
		(size 0.508)
		(drill 0.254)
		(layers "F.Cu" "B.Cu")
		(net "GND")
	)
	(via
		(at 132.350002 -436.051198)
		(size 0.4572)
		(drill 0.2032)
		(layers "F.Cu" "B.Cu")
		(net "GND")
	)
	(via
		(at 54.508146 -260.21665)
		(size 0.4572)
		(drill 0.2032)
		(layers "F.Cu" "B.Cu")
		(net "GND")
	)
	(via
		(at 335.6737 -404.51786)
		(size 0.4572)
		(drill 0.254)
		(layers "F.Cu" "B.Cu")
		(net "GND")
	)
	(via
		(at 336.218276 -67.676268)
		(size 0.6604)
		(drill 0.3302)
		(layers "F.Cu" "B.Cu")
		(net "GND")
	)
	(via
		(at 170.588178 -188.68009)
		(size 0.508)
		(drill 0.254)
		(layers "F.Cu" "B.Cu")
		(net "GND")
	)
	(via
		(at 370.9924 -89.596468)
		(size 0.508)
		(drill 0.254)
		(layers "F.Cu" "B.Cu")
		(net "GND")
	)
	(via
		(at 167.749728 -206.666592)
		(size 0.4572)
		(drill 0.2032)
		(layers "F.Cu" "B.Cu")
		(net "GND")
	)
	(via
		(at 314.092082 -228.766624)
		(size 0.4572)
		(drill 0.2032)
		(layers "F.Cu" "B.Cu")
		(net "GND")
	)
	(via
		(at 180.339746 -285.716726)
		(size 0.4572)
		(drill 0.2032)
		(layers "F.Cu" "B.Cu")
		(net "GND")
	)
	(via
		(at 99.422966 -234.15625)
		(size 0.4572)
		(drill 0.2032)
		(layers "F.Cu" "B.Cu")
		(net "GND")
	)
	(via
		(at 116.783866 -408.74569)
		(size 0.508)
		(drill 0.254)
		(layers "F.Cu" "B.Cu")
		(net "GND")
	)
	(via
		(at 197.637146 -300.166786)
		(size 0.4572)
		(drill 0.2032)
		(layers "F.Cu" "B.Cu")
		(net "GND")
	)
	(via
		(at 161.478976 -288.266632)
		(size 0.4572)
		(drill 0.2032)
		(layers "F.Cu" "B.Cu")
		(net "GND")
	)
	(via
		(at 427.045882 -275.516594)
		(size 0.4572)
		(drill 0.2032)
		(layers "F.Cu" "B.Cu")
		(net "GND")
	)
	(via
		(at 13.345414 -224.516696)
		(size 0.4572)
		(drill 0.2032)
		(layers "F.Cu" "B.Cu")
		(net "GND")
	)
	(via
		(at 460.203042 -68.487036)
		(size 0.508)
		(drill 0.254)
		(layers "F.Cu" "B.Cu")
		(net "GND")
	)
	(via
		(at 262.519414 -289.11677)
		(size 0.4572)
		(drill 0.2032)
		(layers "F.Cu" "B.Cu")
		(net "GND")
	)
	(via
		(at 186.649614 -306.96662)
		(size 0.4572)
		(drill 0.2032)
		(layers "F.Cu" "B.Cu")
		(net "GND")
	)
	(via
		(at 121.617994 -284.033722)
		(size 0.4572)
		(drill 0.2032)
		(layers "F.Cu" "B.Cu")
		(net "GND")
	)
	(via
		(at 123.1392 -78.069948)
		(size 0.508)
		(drill 0.254)
		(layers "F.Cu" "B.Cu")
		(net "GND")
	)
	(via
		(at 145.809462 -410.664152)
		(size 0.4572)
		(drill 0.254)
		(layers "F.Cu" "B.Cu")
		(net "GND")
	)
	(via
		(at 242.537996 -58.946034)
		(size 0.508)
		(drill 0.254)
		(layers "F.Cu" "B.Cu")
		(net "GND")
	)
	(via
		(at 26.223214 -284.866588)
		(size 0.4572)
		(drill 0.2032)
		(layers "F.Cu" "B.Cu")
		(net "GND")
	)
	(via
		(at 196.39788 -75.250548)
		(size 0.508)
		(drill 0.254)
		(layers "F.Cu" "B.Cu")
		(net "GND")
	)
	(via
		(at 186.649614 -245.76659)
		(size 0.4572)
		(drill 0.2032)
		(layers "F.Cu" "B.Cu")
		(net "GND")
	)
	(via
		(at 56.610758 -400.858228)
		(size 0.4064)
		(drill 0.2032)
		(layers "F.Cu" "B.Cu")
		(net "GND")
	)
	(via
		(at 456.048872 -107.018836)
		(size 0.508)
		(drill 0.254)
		(layers "F.Cu" "B.Cu")
		(net "GND")
	)
	(via
		(at 276.373082 -219.41663)
		(size 0.4572)
		(drill 0.2032)
		(layers "F.Cu" "B.Cu")
		(net "GND")
	)
	(via
		(at 191.983614 -280.61666)
		(size 0.4572)
		(drill 0.2032)
		(layers "F.Cu" "B.Cu")
		(net "GND")
	)
	(via
		(at 415.402014 -238.966756)
		(size 0.4572)
		(drill 0.2032)
		(layers "F.Cu" "B.Cu")
		(net "GND")
	)
	(via
		(at 405.648414 -287.416748)
		(size 0.4572)
		(drill 0.2032)
		(layers "F.Cu" "B.Cu")
		(net "GND")
	)
	(via
		(at 398.336262 -409.396184)
		(size 0.4572)
		(drill 0.254)
		(layers "F.Cu" "B.Cu")
		(net "GND")
	)
	(via
		(at 368.210846 -263.125712)
		(size 0.4572)
		(drill 0.2032)
		(layers "F.Cu" "B.Cu")
		(net "GND")
	)
	(via
		(at 56.398414 -194.766692)
		(size 0.4572)
		(drill 0.2032)
		(layers "F.Cu" "B.Cu")
		(net "GND")
	)
	(via
		(at 99.422966 -240.667286)
		(size 0.4572)
		(drill 0.2032)
		(layers "F.Cu" "B.Cu")
		(net "GND")
	)
	(via
		(at 159.321246 -410.664152)
		(size 0.4572)
		(drill 0.254)
		(layers "F.Cu" "B.Cu")
		(net "GND")
	)
	(via
		(at 88.724994 -257.98907)
		(size 0.4572)
		(drill 0.2032)
		(layers "F.Cu" "B.Cu")
		(net "GND")
	)
	(via
		(at 26.223214 -233.86669)
		(size 0.4572)
		(drill 0.2032)
		(layers "F.Cu" "B.Cu")
		(net "GND")
	)
	(via
		(at 214.615014 -301.01667)
		(size 0.4572)
		(drill 0.2032)
		(layers "F.Cu" "B.Cu")
		(net "GND")
	)
	(via
		(at 431.110136 -4.317746)
		(size 0.508)
		(drill 0.254)
		(layers "F.Cu" "B.Cu")
		(net "GND")
	)
	(via
		(at 371.225318 -403.249892)
		(size 0.4572)
		(drill 0.254)
		(layers "F.Cu" "B.Cu")
		(net "GND")
	)
	(via
		(at 16.789146 -208.366614)
		(size 0.4572)
		(drill 0.2032)
		(layers "F.Cu" "B.Cu")
		(net "GND")
	)
	(via
		(at 209.281014 -202.416664)
		(size 0.4572)
		(drill 0.2032)
		(layers "F.Cu" "B.Cu")
		(net "GND")
	)
	(via
		(at 376.99061 -400.858228)
		(size 0.4064)
		(drill 0.2032)
		(layers "F.Cu" "B.Cu")
		(net "GND")
	)
	(via
		(at 56.101996 -112.288066)
		(size 0.508)
		(drill 0.254)
		(layers "F.Cu" "B.Cu")
		(net "GND")
	)
	(via
		(at 396.646908 -12.37488)
		(size 0.508)
		(drill 0.254)
		(layers "F.Cu" "B.Cu")
		(net "GND")
	)
	(via
		(at 94.833694 -286.475424)
		(size 0.4572)
		(drill 0.2032)
		(layers "F.Cu" "B.Cu")
		(net "GND")
	)
	(via
		(at 403.116542 -404.51786)
		(size 0.4572)
		(drill 0.254)
		(layers "F.Cu" "B.Cu")
		(net "GND")
	)
	(via
		(at 91.026742 -335.1911)
		(size 0.49022)
		(drill 0.254)
		(layers "F.Cu" "B.Cu")
		(net "GND")
	)
	(via
		(at 407.858214 -221.96679)
		(size 0.4572)
		(drill 0.2032)
		(layers "F.Cu" "B.Cu")
		(net "GND")
	)
	(via
		(at 54.508146 -265.316716)
		(size 0.4572)
		(drill 0.2032)
		(layers "F.Cu" "B.Cu")
		(net "GND")
	)
	(via
		(at 427.045882 -194.766692)
		(size 0.4572)
		(drill 0.2032)
		(layers "F.Cu" "B.Cu")
		(net "GND")
	)
	(via
		(at 161.808414 -280.61666)
		(size 0.4572)
		(drill 0.2032)
		(layers "F.Cu" "B.Cu")
		(net "GND")
	)
	(via
		(at 84.541106 -400.224244)
		(size 0.4572)
		(drill 0.254)
		(layers "F.Cu" "B.Cu")
		(net "GND")
	)
	(via
		(at 411.958282 -241.516662)
		(size 0.4572)
		(drill 0.2032)
		(layers "F.Cu" "B.Cu")
		(net "GND")
	)
	(via
		(at 372.737634 -226.017328)
		(size 0.4572)
		(drill 0.2032)
		(layers "F.Cu" "B.Cu")
		(net "GND")
	)
	(via
		(at 162.842702 -400.200368)
		(size 0.4572)
		(drill 0.254)
		(layers "F.Cu" "B.Cu")
		(net "GND")
	)
	(via
		(at 20.889214 -233.86669)
		(size 0.4572)
		(drill 0.2032)
		(layers "F.Cu" "B.Cu")
		(net "GND")
	)
	(via
		(at 443.367414 -251.716794)
		(size 0.4572)
		(drill 0.2032)
		(layers "F.Cu" "B.Cu")
		(net "GND")
	)
	(via
		(at 9.70788 -151.348948)
		(size 0.508)
		(drill 0.254)
		(layers "F.Cu" "B.Cu")
		(net "GND")
	)
	(via
		(at 46.964346 -301.866808)
		(size 0.4572)
		(drill 0.2032)
		(layers "F.Cu" "B.Cu")
		(net "GND")
	)
	(via
		(at 44.754546 -251.716794)
		(size 0.4572)
		(drill 0.2032)
		(layers "F.Cu" "B.Cu")
		(net "GND")
	)
	(via
		(at 167.461946 -246.616728)
		(size 0.4572)
		(drill 0.2032)
		(layers "F.Cu" "B.Cu")
		(net "GND")
	)
	(via
		(at 291.460682 -258.516628)
		(size 0.4572)
		(drill 0.2032)
		(layers "F.Cu" "B.Cu")
		(net "GND")
	)
	(via
		(at 431.202592 -117.785896)
		(size 0.508)
		(drill 0.254)
		(layers "F.Cu" "B.Cu")
		(net "GND")
	)
	(via
		(at 457.221082 -232.166668)
		(size 0.4572)
		(drill 0.2032)
		(layers "F.Cu" "B.Cu")
		(net "GND")
	)
	(via
		(at 90.024966 -222.761556)
		(size 0.4572)
		(drill 0.2032)
		(layers "F.Cu" "B.Cu")
		(net "GND")
	)
	(via
		(at 22.147022 -12.37488)
		(size 0.508)
		(drill 0.254)
		(layers "F.Cu" "B.Cu")
		(net "GND")
	)
	(via
		(at 386.541518 -403.249892)
		(size 0.4572)
		(drill 0.254)
		(layers "F.Cu" "B.Cu")
		(net "GND")
	)
	(via
		(at 88.145366 -239.0394)
		(size 0.4572)
		(drill 0.2032)
		(layers "F.Cu" "B.Cu")
		(net "GND")
	)
	(via
		(at 304.122582 -221.116652)
		(size 0.4572)
		(drill 0.2032)
		(layers "F.Cu" "B.Cu")
		(net "GND")
	)
	(via
		(at 37.210746 -197.316598)
		(size 0.4572)
		(drill 0.2032)
		(layers "F.Cu" "B.Cu")
		(net "GND")
	)
	(via
		(at 106.941366 -229.272846)
		(size 0.4572)
		(drill 0.2032)
		(layers "F.Cu" "B.Cu")
		(net "GND")
	)
	(via
		(at 59.250072 -433.899564)
		(size 0.4572)
		(drill 0.2032)
		(layers "F.Cu" "B.Cu")
		(net "GND")
	)
	(via
		(at 39.420546 -285.716726)
		(size 0.4572)
		(drill 0.2032)
		(layers "F.Cu" "B.Cu")
		(net "GND")
	)
	(via
		(at 377.076716 -256.361438)
		(size 0.4572)
		(drill 0.2032)
		(layers "F.Cu" "B.Cu")
		(net "GND")
	)
	(via
		(at 415.295588 -19.759422)
		(size 0.508)
		(drill 0.254)
		(layers "F.Cu" "B.Cu")
		(net "GND")
	)
	(via
		(at 49.83861 -113.68151)
		(size 0.508)
		(drill 0.254)
		(layers "F.Cu" "B.Cu")
		(net "GND")
	)
	(via
		(at 62.051946 -203.266802)
		(size 0.4572)
		(drill 0.2032)
		(layers "F.Cu" "B.Cu")
		(net "GND")
	)
	(via
		(at 216.824814 -230.466646)
		(size 0.4572)
		(drill 0.2032)
		(layers "F.Cu" "B.Cu")
		(net "GND")
	)
	(via
		(at 343.14638 -406.370536)
		(size 0.4572)
		(drill 0.254)
		(layers "F.Cu" "B.Cu")
		(net "GND")
	)
	(via
		(at 277.607014 -287.416748)
		(size 0.4572)
		(drill 0.2032)
		(layers "F.Cu" "B.Cu")
		(net "GND")
	)
	(via
		(at 159.918146 -300.166786)
		(size 0.4572)
		(drill 0.2032)
		(layers "F.Cu" "B.Cu")
		(net "GND")
	)
	(via
		(at 159.682434 -407.00452)
		(size 0.4064)
		(drill 0.2032)
		(layers "F.Cu" "B.Cu")
		(net "GND")
	)
	(via
		(at 209.281014 -291.666676)
		(size 0.4572)
		(drill 0.2032)
		(layers "F.Cu" "B.Cu")
		(net "GND")
	)
	(via
		(at 214.615014 -277.216616)
		(size 0.4572)
		(drill 0.2032)
		(layers "F.Cu" "B.Cu")
		(net "GND")
	)
	(via
		(at 424.347386 -364.071662)
		(size 0.49022)
		(drill 0.254)
		(layers "F.Cu" "B.Cu")
		(net "GND")
	)
	(via
		(at 20.416266 -17.61236)
		(size 0.508)
		(drill 0.254)
		(layers "F.Cu" "B.Cu")
		(net "GND")
	)
	(via
		(at 374.19153 -410.030168)
		(size 0.4064)
		(drill 0.2032)
		(layers "F.Cu" "B.Cu")
		(net "GND")
	)
	(via
		(at 411.958282 -269.566644)
		(size 0.4572)
		(drill 0.2032)
		(layers "F.Cu" "B.Cu")
		(net "GND")
	)
	(via
		(at 187.883546 -231.316784)
		(size 0.4572)
		(drill 0.2032)
		(layers "F.Cu" "B.Cu")
		(net "GND")
	)
	(via
		(at 181.31028 -123.104148)
		(size 0.508)
		(drill 0.254)
		(layers "F.Cu" "B.Cu")
		(net "GND")
	)
	(via
		(at 288.094166 -360.83621)
		(size 0.49022)
		(drill 0.254)
		(layers "F.Cu" "B.Cu")
		(net "GND")
	)
	(via
		(at 445.577214 -220.266768)
		(size 0.4572)
		(drill 0.2032)
		(layers "F.Cu" "B.Cu")
		(net "GND")
	)
	(via
		(at 46.964346 -296.766742)
		(size 0.4572)
		(drill 0.2032)
		(layers "F.Cu" "B.Cu")
		(net "GND")
	)
	(via
		(at 135.135112 -217.878406)
		(size 0.4572)
		(drill 0.2032)
		(layers "F.Cu" "B.Cu")
		(net "GND")
	)
	(via
		(at 130.906012 -239.853216)
		(size 0.4572)
		(drill 0.2032)
		(layers "F.Cu" "B.Cu")
		(net "GND")
	)
	(via
		(at 136.184894 -273.453098)
		(size 0.4572)
		(drill 0.2032)
		(layers "F.Cu" "B.Cu")
		(net "GND")
	)
	(via
		(at 161.125662 -407.638504)
		(size 0.4572)
		(drill 0.254)
		(layers "F.Cu" "B.Cu")
		(net "GND")
	)
	(via
		(at 403.116542 -403.249892)
		(size 0.4572)
		(drill 0.254)
		(layers "F.Cu" "B.Cu")
		(net "GND")
	)
	(via
		(at 29.666946 -309.51678)
		(size 0.4572)
		(drill 0.2032)
		(layers "F.Cu" "B.Cu")
		(net "GND")
	)
	(via
		(at 97.653348 -279.964134)
		(size 0.4572)
		(drill 0.2032)
		(layers "F.Cu" "B.Cu")
		(net "GND")
	)
	(via
		(at 18.54708 -7.215124)
		(size 0.508)
		(drill 0.254)
		(layers "F.Cu" "B.Cu")
		(net "GND")
	)
	(via
		(at 407.34996 -426.69968)
		(size 0.4572)
		(drill 0.2032)
		(layers "F.Cu" "B.Cu")
		(net "GND")
	)
	(via
		(at 181.407308 -49.887886)
		(size 0.508)
		(drill 0.254)
		(layers "F.Cu" "B.Cu")
		(net "GND")
	)
	(via
		(at 464.764882 -247.466612)
		(size 0.4572)
		(drill 0.2032)
		(layers "F.Cu" "B.Cu")
		(net "GND")
	)
	(via
		(at 345.15171 -46.350936)
		(size 0.4572)
		(drill 0.2032)
		(layers "F.Cu" "B.Cu")
		(net "GND")
	)
	(via
		(at 98.122994 -266.128246)
		(size 0.4572)
		(drill 0.2032)
		(layers "F.Cu" "B.Cu")
		(net "GND")
	)
	(via
		(at 327.250044 -425.547282)
		(size 0.4572)
		(drill 0.2032)
		(layers "F.Cu" "B.Cu")
		(net "GND")
	)
	(via
		(at 91.544648 -269.38351)
		(size 0.4572)
		(drill 0.2032)
		(layers "F.Cu" "B.Cu")
		(net "GND")
	)
	(via
		(at 37.345874 -179.53609)
		(size 0.508)
		(drill 0.254)
		(layers "F.Cu" "B.Cu")
		(net "GND")
	)
	(via
		(at 427.766988 -12.37488)
		(size 0.508)
		(drill 0.254)
		(layers "F.Cu" "B.Cu")
		(net "GND")
	)
	(via
		(at 58.608214 -269.566644)
		(size 0.4572)
		(drill 0.2032)
		(layers "F.Cu" "B.Cu")
		(net "GND")
	)
	(via
		(at 54.12105 -350.255332)
		(size 0.508)
		(drill 0.254)
		(layers "F.Cu" "B.Cu")
		(net "GND")
	)
	(via
		(at 261.285482 -275.516594)
		(size 0.4572)
		(drill 0.2032)
		(layers "F.Cu" "B.Cu")
		(net "GND")
	)
	(via
		(at 221.1578 -99.21748)
		(size 0.508)
		(drill 0.254)
		(layers "F.Cu" "B.Cu")
		(net "GND")
	)
	(via
		(at 411.958282 -314.616592)
		(size 0.4572)
		(drill 0.2032)
		(layers "F.Cu" "B.Cu")
		(net "GND")
	)
	(via
		(at 126.350014 -433.899564)
		(size 0.4572)
		(drill 0.2032)
		(layers "F.Cu" "B.Cu")
		(net "GND")
	)
	(via
		(at 402.786596 -17.601438)
		(size 0.508)
		(drill 0.254)
		(layers "F.Cu" "B.Cu")
		(net "GND")
	)
	(via
		(at 384.350006 -427.699678)
		(size 0.4572)
		(drill 0.2032)
		(layers "F.Cu" "B.Cu")
		(net "GND")
	)
	(via
		(at 460.664814 -201.56678)
		(size 0.4572)
		(drill 0.2032)
		(layers "F.Cu" "B.Cu")
		(net "GND")
	)
	(via
		(at 132.425948 -263.686544)
		(size 0.4572)
		(drill 0.2032)
		(layers "F.Cu" "B.Cu")
		(net "GND")
	)
	(via
		(at 29.666946 -242.3668)
		(size 0.4572)
		(drill 0.2032)
		(layers "F.Cu" "B.Cu")
		(net "GND")
	)
	(via
		(at 373.317516 -277.522432)
		(size 0.4572)
		(drill 0.2032)
		(layers "F.Cu" "B.Cu")
		(net "GND")
	)
	(via
		(at 127.616966 -234.15625)
		(size 0.4572)
		(drill 0.2032)
		(layers "F.Cu" "B.Cu")
		(net "GND")
	)
	(via
		(at 18.679414 -228.766624)
		(size 0.4572)
		(drill 0.2032)
		(layers "F.Cu" "B.Cu")
		(net "GND")
	)
	(via
		(at 299.004482 -219.41663)
		(size 0.4572)
		(drill 0.2032)
		(layers "F.Cu" "B.Cu")
		(net "GND")
	)
	(via
		(at 121.038366 -219.506038)
		(size 0.4572)
		(drill 0.2032)
		(layers "F.Cu" "B.Cu")
		(net "GND")
	)
	(via
		(at 59.250072 -431.451258)
		(size 0.4572)
		(drill 0.2032)
		(layers "F.Cu" "B.Cu")
		(net "GND")
	)
	(via
		(at 289.250882 -233.86669)
		(size 0.4572)
		(drill 0.2032)
		(layers "F.Cu" "B.Cu")
		(net "GND")
	)
	(via
		(at 450.911214 -216.016586)
		(size 0.4572)
		(drill 0.2032)
		(layers "F.Cu" "B.Cu")
		(net "GND")
	)
	(via
		(at 102.242366 -216.25052)
		(size 0.4572)
		(drill 0.2032)
		(layers "F.Cu" "B.Cu")
		(net "GND")
	)
	(via
		(at 212.724746 -204.96657)
		(size 0.4572)
		(drill 0.2032)
		(layers "F.Cu" "B.Cu")
		(net "GND")
	)
	(via
		(at 380.256034 -234.15625)
		(size 0.4572)
		(drill 0.2032)
		(layers "F.Cu" "B.Cu")
		(net "GND")
	)
	(via
		(at 430.01184 -359.455466)
		(size 0.508)
		(drill 0.254)
		(layers "F.Cu" "B.Cu")
		(net "GND")
	)
	(via
		(at 215.34882 -112.748568)
		(size 0.508)
		(drill 0.254)
		(layers "F.Cu" "B.Cu")
		(net "GND")
	)
	(via
		(at 369.558062 -272.639282)
		(size 0.4572)
		(drill 0.2032)
		(layers "F.Cu" "B.Cu")
		(net "GND")
	)
	(via
		(at 449.677282 -245.76659)
		(size 0.4572)
		(drill 0.2032)
		(layers "F.Cu" "B.Cu")
		(net "GND")
	)
	(via
		(at 274.901152 -323.429376)
		(size 0.4572)
		(drill 0.2032)
		(layers "F.Cu" "B.Cu")
		(net "GND")
	)
	(via
		(at 149.349968 -433.747164)
		(size 0.4572)
		(drill 0.2032)
		(layers "F.Cu" "B.Cu")
		(net "GND")
	)
	(via
		(at 16.33855 -181.781196)
		(size 0.508)
		(drill 0.254)
		(layers "F.Cu" "B.Cu")
		(net "GND")
	)
	(via
		(at 319.25006 -437.49976)
		(size 0.4572)
		(drill 0.2032)
		(layers "F.Cu" "B.Cu")
		(net "GND")
	)
	(via
		(at 291.64788 -127.345948)
		(size 0.508)
		(drill 0.254)
		(layers "F.Cu" "B.Cu")
		(net "GND")
	)
	(via
		(at 264.729214 -285.716726)
		(size 0.4572)
		(drill 0.2032)
		(layers "F.Cu" "B.Cu")
		(net "GND")
	)
	(via
		(at 385.064762 -273.453098)
		(size 0.4318)
		(drill 0.2032)
		(layers "F.Cu" "B.Cu")
		(net "GND")
	)
	(via
		(at 341.921338 -53.148992)
		(size 0.4572)
		(drill 0.2032)
		(layers "F.Cu" "B.Cu")
		(net "GND")
	)
	(via
		(at 39.420546 -272.116804)
		(size 0.4572)
		(drill 0.2032)
		(layers "F.Cu" "B.Cu")
		(net "GND")
	)
	(via
		(at 350.292416 -278.336502)
		(size 0.4572)
		(drill 0.2032)
		(layers "F.Cu" "B.Cu")
		(net "GND")
	)
	(via
		(at 28.216098 -132.093208)
		(size 0.508)
		(drill 0.254)
		(layers "F.Cu" "B.Cu")
		(net "GND")
	)
	(via
		(at 268.829282 -284.866588)
		(size 0.4572)
		(drill 0.2032)
		(layers "F.Cu" "B.Cu")
		(net "GND")
	)
	(via
		(at 22.123146 -313.766708)
		(size 0.4572)
		(drill 0.2032)
		(layers "F.Cu" "B.Cu")
		(net "GND")
	)
	(via
		(at 125.625606 -410.664152)
		(size 0.4572)
		(drill 0.254)
		(layers "F.Cu" "B.Cu")
		(net "GND")
	)
	(via
		(at 384.737102 -401.492212)
		(size 0.4572)
		(drill 0.254)
		(layers "F.Cu" "B.Cu")
		(net "GND")
	)
	(via
		(at 352.171762 -283.219906)
		(size 0.4572)
		(drill 0.2032)
		(layers "F.Cu" "B.Cu")
		(net "GND")
	)
	(via
		(at 445.577214 -206.666592)
		(size 0.4572)
		(drill 0.2032)
		(layers "F.Cu" "B.Cu")
		(net "GND")
	)
	(via
		(at 338.90458 -245.55069)
		(size 0.4572)
		(drill 0.2032)
		(layers "F.Cu" "B.Cu")
		(net "GND")
	)
	(via
		(at 382.35001 -433.899564)
		(size 0.4572)
		(drill 0.2032)
		(layers "F.Cu" "B.Cu")
		(net "GND")
	)
	(via
		(at 398.336262 -406.370536)
		(size 0.4572)
		(drill 0.254)
		(layers "F.Cu" "B.Cu")
		(net "GND")
	)
	(via
		(at 63.942214 -308.666642)
		(size 0.4572)
		(drill 0.2032)
		(layers "F.Cu" "B.Cu")
		(net "GND")
	)
	(via
		(at 332.250034 -425.547282)
		(size 0.4572)
		(drill 0.2032)
		(layers "F.Cu" "B.Cu")
		(net "GND")
	)
	(via
		(at 205.180946 -195.616576)
		(size 0.4572)
		(drill 0.2032)
		(layers "F.Cu" "B.Cu")
		(net "GND")
	)
	(via
		(at 332.250034 -436.347362)
		(size 0.4572)
		(drill 0.2032)
		(layers "F.Cu" "B.Cu")
		(net "GND")
	)
	(via
		(at 47.782226 -403.249892)
		(size 0.4572)
		(drill 0.254)
		(layers "F.Cu" "B.Cu")
		(net "GND")
	)
	(via
		(at 11.135614 -306.96662)
		(size 0.4572)
		(drill 0.2032)
		(layers "F.Cu" "B.Cu")
		(net "GND")
	)
	(via
		(at 210.514946 -290.816792)
		(size 0.4572)
		(drill 0.2032)
		(layers "F.Cu" "B.Cu")
		(net "GND")
	)
	(via
		(at 266.619482 -196.466714)
		(size 0.4572)
		(drill 0.2032)
		(layers "F.Cu" "B.Cu")
		(net "GND")
	)
	(via
		(at 79.67345 -404.51786)
		(size 0.4572)
		(drill 0.254)
		(layers "F.Cu" "B.Cu")
		(net "GND")
	)
	(via
		(at 276.373082 -233.86669)
		(size 0.4572)
		(drill 0.2032)
		(layers "F.Cu" "B.Cu")
		(net "GND")
	)
	(via
		(at 63.726314 -284.866588)
		(size 0.4572)
		(drill 0.2032)
		(layers "F.Cu" "B.Cu")
		(net "GND")
	)
	(via
		(at 43.62577 -4.962652)
		(size 0.508)
		(drill 0.254)
		(layers "F.Cu" "B.Cu")
		(net "GND")
	)
	(via
		(at 413.349948 -427.699678)
		(size 0.4572)
		(drill 0.2032)
		(layers "F.Cu" "B.Cu")
		(net "GND")
	)
	(via
		(at 380.25578 -245.55069)
		(size 0.4572)
		(drill 0.2032)
		(layers "F.Cu" "B.Cu")
		(net "GND")
	)
	(via
		(at 62.051946 -250.016772)
		(size 0.4572)
		(drill 0.2032)
		(layers "F.Cu" "B.Cu")
		(net "GND")
	)
	(via
		(at 206.7306 -68.503292)
		(size 0.508)
		(drill 0.254)
		(layers "F.Cu" "B.Cu")
		(net "GND")
	)
	(via
		(at 172.795946 -210.916774)
		(size 0.4572)
		(drill 0.2032)
		(layers "F.Cu" "B.Cu")
		(net "GND")
	)
	(via
		(at 291.653722 -359.442004)
		(size 0.508)
		(drill 0.254)
		(layers "F.Cu" "B.Cu")
		(net "GND")
	)
	(via
		(at 110.340648 -288.993326)
		(size 0.4572)
		(drill 0.2032)
		(layers "F.Cu" "B.Cu")
		(net "GND")
	)
	(via
		(at 418.349938 -360.94162)
		(size 0.49022)
		(drill 0.254)
		(layers "F.Cu" "B.Cu")
		(net "GND")
	)
	(via
		(at 20.889214 -269.566644)
		(size 0.4572)
		(drill 0.2032)
		(layers "F.Cu" "B.Cu")
		(net "GND")
	)
	(via
		(at 458.455014 -217.716608)
		(size 0.4572)
		(drill 0.2032)
		(layers "F.Cu" "B.Cu")
		(net "GND")
	)
	(via
		(at 334.25003 -426.54728)
		(size 0.4572)
		(drill 0.2032)
		(layers "F.Cu" "B.Cu")
		(net "GND")
	)
	(via
		(at 48.854614 -305.266598)
		(size 0.4572)
		(drill 0.2032)
		(layers "F.Cu" "B.Cu")
		(net "GND")
	)
	(via
		(at 63.942214 -204.116686)
		(size 0.4572)
		(drill 0.2032)
		(layers "F.Cu" "B.Cu")
		(net "GND")
	)
	(via
		(at 205.180946 -306.116736)
		(size 0.4572)
		(drill 0.2032)
		(layers "F.Cu" "B.Cu")
		(net "GND")
	)
	(via
		(at 96.133412 -230.086662)
		(size 0.4572)
		(drill 0.2032)
		(layers "F.Cu" "B.Cu")
		(net "GND")
	)
	(via
		(at 348.302834 -247.178322)
		(size 0.4572)
		(drill 0.2032)
		(layers "F.Cu" "B.Cu")
		(net "GND")
	)
	(via
		(at 244.73408 -54.533546)
		(size 0.508)
		(drill 0.254)
		(layers "F.Cu" "B.Cu")
		(net "GND")
	)
	(via
		(at 32.30753 -433.923948)
		(size 0.508)
		(drill 0.254)
		(layers "F.Cu" "B.Cu")
		(net "GND")
	)
	(via
		(at 134.775448 -288.917126)
		(size 0.4572)
		(drill 0.2032)
		(layers "F.Cu" "B.Cu")
		(net "GND")
	)
	(via
		(at 392.34999 -432.451256)
		(size 0.4572)
		(drill 0.2032)
		(layers "F.Cu" "B.Cu")
		(net "GND")
	)
	(via
		(at 360.05008 -215.436704)
		(size 0.4572)
		(drill 0.2032)
		(layers "F.Cu" "B.Cu")
		(net "GND")
	)
	(via
		(at 360.491024 -365.825532)
		(size 0.508)
		(drill 0.254)
		(layers "F.Cu" "B.Cu")
		(net "GND")
	)
	(via
		(at 130.546348 -281.59202)
		(size 0.4572)
		(drill 0.2032)
		(layers "F.Cu" "B.Cu")
		(net "GND")
	)
	(via
		(at 457.221082 -289.966654)
		(size 0.4572)
		(drill 0.2032)
		(layers "F.Cu" "B.Cu")
		(net "GND")
	)
	(via
		(at 201.737214 -264.466578)
		(size 0.4572)
		(drill 0.2032)
		(layers "F.Cu" "B.Cu")
		(net "GND")
	)
	(via
		(at 262.519414 -204.96657)
		(size 0.4572)
		(drill 0.2032)
		(layers "F.Cu" "B.Cu")
		(net "GND")
	)
	(via
		(at 405.648414 -227.066602)
		(size 0.4572)
		(drill 0.2032)
		(layers "F.Cu" "B.Cu")
		(net "GND")
	)
	(via
		(at 7.035546 -251.716794)
		(size 0.4572)
		(drill 0.2032)
		(layers "F.Cu" "B.Cu")
		(net "GND")
	)
	(via
		(at 187.883546 -263.616694)
		(size 0.4572)
		(drill 0.2032)
		(layers "F.Cu" "B.Cu")
		(net "GND")
	)
	(via
		(at 54.508146 -309.51678)
		(size 0.4572)
		(drill 0.2032)
		(layers "F.Cu" "B.Cu")
		(net "GND")
	)
	(via
		(at 115.415822 -245.396766)
		(size 0.4572)
		(drill 0.2032)
		(layers "F.Cu" "B.Cu")
		(net "GND")
	)
	(via
		(at 456.052936 -380.085854)
		(size 0.508)
		(drill 0.254)
		(layers "F.Cu" "B.Cu")
		(net "GND")
	)
	(via
		(at 283.916882 -267.866622)
		(size 0.4572)
		(drill 0.2032)
		(layers "F.Cu" "B.Cu")
		(net "GND")
	)
	(via
		(at 252.616462 -92.890594)
		(size 0.508)
		(drill 0.254)
		(layers "F.Cu" "B.Cu")
		(net "GND")
	)
	(via
		(at 124.437394 -277.522432)
		(size 0.4572)
		(drill 0.2032)
		(layers "F.Cu" "B.Cu")
		(net "GND")
	)
	(via
		(at 18.679414 -226.216718)
		(size 0.4572)
		(drill 0.2032)
		(layers "F.Cu" "B.Cu")
		(net "GND")
	)
	(via
		(at 89.01938 -342.65362)
		(size 0.508)
		(drill 0.254)
		(layers "F.Cu" "B.Cu")
		(net "GND")
	)
	(via
		(at 2.764536 -259.510022)
		(size 0.508)
		(drill 0.254)
		(layers "F.Cu" "B.Cu")
		(net "GND")
	)
	(via
		(at 121.37009 -425.059348)
		(size 0.508)
		(drill 0.254)
		(layers "F.Cu" "B.Cu")
		(net "GND")
	)
	(via
		(at 84.20481 -336.982816)
		(size 0.508)
		(drill 0.254)
		(layers "F.Cu" "B.Cu")
		(net "GND")
	)
	(via
		(at 171.332398 -352.404172)
		(size 0.49022)
		(drill 0.254)
		(layers "F.Cu" "B.Cu")
		(net "GND")
	)
	(via
		(at 181.7624 -95.367348)
		(size 0.508)
		(drill 0.254)
		(layers "F.Cu" "B.Cu")
		(net "GND")
	)
	(via
		(at 348.412562 -289.807142)
		(size 0.4572)
		(drill 0.2032)
		(layers "F.Cu" "B.Cu")
		(net "GND")
	)
	(via
		(at 460.664814 -276.366732)
		(size 0.4572)
		(drill 0.2032)
		(layers "F.Cu" "B.Cu")
		(net "GND")
	)
	(via
		(at 48.761904 -173.818804)
		(size 0.508)
		(drill 0.254)
		(layers "F.Cu" "B.Cu")
		(net "GND")
	)
	(via
		(at 411.958282 -291.666676)
		(size 0.4572)
		(drill 0.2032)
		(layers "F.Cu" "B.Cu")
		(net "GND")
	)
	(via
		(at 51.064414 -314.616592)
		(size 0.4572)
		(drill 0.2032)
		(layers "F.Cu" "B.Cu")
		(net "GND")
	)
	(via
		(at 212.724746 -296.766742)
		(size 0.4572)
		(drill 0.2032)
		(layers "F.Cu" "B.Cu")
		(net "GND")
	)
	(via
		(at 405.349964 -437.34736)
		(size 0.4572)
		(drill 0.2032)
		(layers "F.Cu" "B.Cu")
		(net "GND")
	)
	(via
		(at 414.85947 -180.810154)
		(size 0.49022)
		(drill 0.254)
		(layers "F.Cu" "B.Cu")
		(net "GND")
	)
	(via
		(at 110.952788 -297.19778)
		(size 0.508)
		(drill 0.254)
		(layers "F.Cu" "B.Cu")
		(net "GND")
	)
	(via
		(at 343.133934 -217.064336)
		(size 0.4572)
		(drill 0.2032)
		(layers "F.Cu" "B.Cu")
		(net "GND")
	)
	(via
		(at 14.579346 -270.416782)
		(size 0.4572)
		(drill 0.2032)
		(layers "F.Cu" "B.Cu")
		(net "GND")
	)
	(via
		(at 44.754546 -217.716608)
		(size 0.4572)
		(drill 0.2032)
		(layers "F.Cu" "B.Cu")
		(net "GND")
	)
	(via
		(at 138.424666 -220.319854)
		(size 0.4572)
		(drill 0.2032)
		(layers "F.Cu" "B.Cu")
		(net "GND")
	)
	(via
		(at 56.049672 -147.150074)
		(size 0.49022)
		(drill 0.254)
		(layers "F.Cu" "B.Cu")
		(net "GND")
	)
	(via
		(at 121.978166 -222.761556)
		(size 0.4572)
		(drill 0.2032)
		(layers "F.Cu" "B.Cu")
		(net "GND")
	)
	(via
		(at 423.195242 -380.329948)
		(size 0.508)
		(drill 0.254)
		(layers "F.Cu" "B.Cu")
		(net "GND")
	)
	(via
		(at 330.990448 -403.883876)
		(size 0.4064)
		(drill 0.2032)
		(layers "F.Cu" "B.Cu")
		(net "GND")
	)
	(via
		(at 214.615014 -210.066636)
		(size 0.4572)
		(drill 0.2032)
		(layers "F.Cu" "B.Cu")
		(net "GND")
	)
	(via
		(at 212.724746 -306.116736)
		(size 0.4572)
		(drill 0.2032)
		(layers "F.Cu" "B.Cu")
		(net "GND")
	)
	(via
		(at 339.484462 -266.128246)
		(size 0.4572)
		(drill 0.2032)
		(layers "F.Cu" "B.Cu")
		(net "GND")
	)
	(via
		(at 37.210746 -265.316716)
		(size 0.4572)
		(drill 0.2032)
		(layers "F.Cu" "B.Cu")
		(net "GND")
	)
	(via
		(at 257.095498 -37.782246)
		(size 0.508)
		(drill 0.254)
		(layers "F.Cu" "B.Cu")
		(net "GND")
	)
	(via
		(at 151.574754 -410.030168)
		(size 0.4064)
		(drill 0.2032)
		(layers "F.Cu" "B.Cu")
		(net "GND")
	)
	(via
		(at 120.098566 -222.761556)
		(size 0.4572)
		(drill 0.2032)
		(layers "F.Cu" "B.Cu")
		(net "GND")
	)
	(via
		(at 335.270856 -337.692238)
		(size 0.49022)
		(drill 0.254)
		(layers "F.Cu" "B.Cu")
		(net "GND")
	)
	(via
		(at 266.619482 -310.366664)
		(size 0.4572)
		(drill 0.2032)
		(layers "F.Cu" "B.Cu")
		(net "GND")
	)
	(via
		(at 160.211516 -216.016586)
		(size 0.4572)
		(drill 0.2032)
		(layers "F.Cu" "B.Cu")
		(net "GND")
	)
	(via
		(at 337.581748 -55.028846)
		(size 0.4572)
		(drill 0.2032)
		(layers "F.Cu" "B.Cu")
		(net "GND")
	)
	(via
		(at 460.664814 -250.016772)
		(size 0.4572)
		(drill 0.2032)
		(layers "F.Cu" "B.Cu")
		(net "GND")
	)
	(via
		(at 122.108214 -331.776832)
		(size 0.49022)
		(drill 0.254)
		(layers "F.Cu" "B.Cu")
		(net "GND")
	)
	(via
		(at 409.748482 -215.166702)
		(size 0.4572)
		(drill 0.2032)
		(layers "F.Cu" "B.Cu")
		(net "GND")
	)
	(via
		(at 458.455014 -195.616576)
		(size 0.4572)
		(drill 0.2032)
		(layers "F.Cu" "B.Cu")
		(net "GND")
	)
	(via
		(at 376.96648 -238.225584)
		(size 0.4572)
		(drill 0.2032)
		(layers "F.Cu" "B.Cu")
		(net "GND")
	)
	(via
		(at 128.196594 -284.033722)
		(size 0.4572)
		(drill 0.2032)
		(layers "F.Cu" "B.Cu")
		(net "GND")
	)
	(via
		(at 33.767014 -305.266598)
		(size 0.4572)
		(drill 0.2032)
		(layers "F.Cu" "B.Cu")
		(net "GND")
	)
	(via
		(at 48.854614 -261.066788)
		(size 0.4572)
		(drill 0.2032)
		(layers "F.Cu" "B.Cu")
		(net "GND")
	)
	(via
		(at 383.075434 -222.761556)
		(size 0.4572)
		(drill 0.2032)
		(layers "F.Cu" "B.Cu")
		(net "GND")
	)
	(via
		(at 84.250022 -432.747166)
		(size 0.4572)
		(drill 0.2032)
		(layers "F.Cu" "B.Cu")
		(net "GND")
	)
	(via
		(at 72.288146 -403.249892)
		(size 0.4572)
		(drill 0.254)
		(layers "F.Cu" "B.Cu")
		(net "GND")
	)
	(via
		(at 131.956048 -279.150318)
		(size 0.4572)
		(drill 0.2032)
		(layers "F.Cu" "B.Cu")
		(net "GND")
	)
	(via
		(at 360.603038 -201.20991)
		(size 0.6604)
		(drill 0.3302)
		(layers "F.Cu" "B.Cu")
		(net "GND")
	)
	(via
		(at 40.691054 -354.109528)
		(size 0.49022)
		(drill 0.254)
		(layers "F.Cu" "B.Cu")
		(net "GND")
	)
	(via
		(at 160.227772 -48.576992)
		(size 0.508)
		(drill 0.254)
		(layers "F.Cu" "B.Cu")
		(net "GND")
	)
	(via
		(at 121.23293 -334.282034)
		(size 0.49022)
		(drill 0.254)
		(layers "F.Cu" "B.Cu")
		(net "GND")
	)
	(via
		(at 84.40039 -53.494686)
		(size 0.508)
		(drill 0.254)
		(layers "F.Cu" "B.Cu")
		(net "GND")
	)
	(via
		(at 383.655062 -280.778204)
		(size 0.4572)
		(drill 0.2032)
		(layers "F.Cu" "B.Cu")
		(net "GND")
	)
	(via
		(at 209.281014 -233.86669)
		(size 0.4572)
		(drill 0.2032)
		(layers "F.Cu" "B.Cu")
		(net "GND")
	)
	(via
		(at 167.461946 -233.016806)
		(size 0.4572)
		(drill 0.2032)
		(layers "F.Cu" "B.Cu")
		(net "GND")
	)
	(via
		(at 422.945814 -216.016586)
		(size 0.4572)
		(drill 0.2032)
		(layers "F.Cu" "B.Cu")
		(net "GND")
	)
	(via
		(at 375.548906 -171.567348)
		(size 0.508)
		(drill 0.254)
		(layers "F.Cu" "B.Cu")
		(net "GND")
	)
	(via
		(at 264.729214 -208.366614)
		(size 0.4572)
		(drill 0.2032)
		(layers "F.Cu" "B.Cu")
		(net "GND")
	)
	(via
		(at 52.911248 -146.33575)
		(size 0.49022)
		(drill 0.254)
		(layers "F.Cu" "B.Cu")
		(net "GND")
	)
	(via
		(at 380.256034 -243.922804)
		(size 0.4572)
		(drill 0.2032)
		(layers "F.Cu" "B.Cu")
		(net "GND")
	)
	(via
		(at 46.964346 -203.266802)
		(size 0.4572)
		(drill 0.2032)
		(layers "F.Cu" "B.Cu")
		(net "GND")
	)
	(via
		(at 63.46444 -131.628388)
		(size 0.508)
		(drill 0.254)
		(layers "F.Cu" "B.Cu")
		(net "GND")
	)
	(via
		(at 213.168484 -323.358256)
		(size 0.4572)
		(drill 0.2032)
		(layers "F.Cu" "B.Cu")
		(net "GND")
	)
	(via
		(at 332.250034 -435.0512)
		(size 0.4572)
		(drill 0.2032)
		(layers "F.Cu" "B.Cu")
		(net "GND")
	)
	(via
		(at 164.018214 -294.216582)
		(size 0.4572)
		(drill 0.2032)
		(layers "F.Cu" "B.Cu")
		(net "GND")
	)
	(via
		(at 100.362766 -226.017328)
		(size 0.4572)
		(drill 0.2032)
		(layers "F.Cu" "B.Cu")
		(net "GND")
	)
	(via
		(at 384.863848 -343.48293)
		(size 0.49022)
		(drill 0.254)
		(layers "F.Cu" "B.Cu")
		(net "GND")
	)
	(via
		(at 201.220832 -439.905394)
		(size 0.508)
		(drill 0.254)
		(layers "F.Cu" "B.Cu")
		(net "GND")
	)
	(via
		(at 171.562014 -301.01667)
		(size 0.4572)
		(drill 0.2032)
		(layers "F.Cu" "B.Cu")
		(net "GND")
	)
	(via
		(at 375.836434 -357.609394)
		(size 0.508)
		(drill 0.254)
		(layers "F.Cu" "B.Cu")
		(net "GND")
	)
	(via
		(at 152.20188 -112.867948)
		(size 0.508)
		(drill 0.254)
		(layers "F.Cu" "B.Cu")
		(net "GND")
	)
	(via
		(at 255.580134 -97.26803)
		(size 0.508)
		(drill 0.254)
		(layers "F.Cu" "B.Cu")
		(net "GND")
	)
	(via
		(at 362.509816 -276.708616)
		(size 0.4572)
		(drill 0.2032)
		(layers "F.Cu" "B.Cu")
		(net "GND")
	)
	(via
		(at 413.349948 -430.147222)
		(size 0.4572)
		(drill 0.2032)
		(layers "F.Cu" "B.Cu")
		(net "GND")
	)
	(via
		(at 93.27261 -410.664152)
		(size 0.4572)
		(drill 0.254)
		(layers "F.Cu" "B.Cu")
		(net "GND")
	)
	(via
		(at 55.817008 -356.996746)
		(size 0.508)
		(drill 0.254)
		(layers "F.Cu" "B.Cu")
		(net "GND")
	)
	(via
		(at 367.678462 -282.405836)
		(size 0.4572)
		(drill 0.2032)
		(layers "F.Cu" "B.Cu")
		(net "GND")
	)
	(via
		(at 91.544394 -275.8948)
		(size 0.4572)
		(drill 0.2032)
		(layers "F.Cu" "B.Cu")
		(net "GND")
	)
	(via
		(at 52.298346 -204.96657)
		(size 0.4572)
		(drill 0.2032)
		(layers "F.Cu" "B.Cu")
		(net "GND")
	)
	(via
		(at 7.035546 -250.016772)
		(size 0.4572)
		(drill 0.2032)
		(layers "F.Cu" "B.Cu")
		(net "GND")
	)
	(via
		(at 159.828992 -110.990888)
		(size 0.508)
		(drill 0.254)
		(layers "F.Cu" "B.Cu")
		(net "GND")
	)
	(via
		(at 312.972196 -400.224244)
		(size 0.4572)
		(drill 0.254)
		(layers "F.Cu" "B.Cu")
		(net "GND")
	)
	(via
		(at 378.20854 -335.187036)
		(size 0.49022)
		(drill 0.254)
		(layers "F.Cu" "B.Cu")
		(net "GND")
	)
	(via
		(at 212.724746 -287.416748)
		(size 0.4572)
		(drill 0.2032)
		(layers "F.Cu" "B.Cu")
		(net "GND")
	)
	(via
		(at 285.150814 -203.266802)
		(size 0.4572)
		(drill 0.2032)
		(layers "F.Cu" "B.Cu")
		(net "GND")
	)
	(via
		(at 432.379882 -308.666642)
		(size 0.4572)
		(drill 0.2032)
		(layers "F.Cu" "B.Cu")
		(net "GND")
	)
	(via
		(at 379.743716 -336.766662)
		(size 0.49022)
		(drill 0.254)
		(layers "F.Cu" "B.Cu")
		(net "GND")
	)
	(via
		(at 450.911214 -248.31675)
		(size 0.4572)
		(drill 0.2032)
		(layers "F.Cu" "B.Cu")
		(net "GND")
	)
	(via
		(at 106.471466 -226.831144)
		(size 0.4572)
		(drill 0.2032)
		(layers "F.Cu" "B.Cu")
		(net "GND")
	)
	(via
		(at 63.726314 -303.566576)
		(size 0.4572)
		(drill 0.2032)
		(layers "F.Cu" "B.Cu")
		(net "GND")
	)
	(via
		(at 279.816814 -298.466764)
		(size 0.4572)
		(drill 0.2032)
		(layers "F.Cu" "B.Cu")
		(net "GND")
	)
	(via
		(at 289.250882 -205.816708)
		(size 0.4572)
		(drill 0.2032)
		(layers "F.Cu" "B.Cu")
		(net "GND")
	)
	(via
		(at 97.073466 -220.319854)
		(size 0.4572)
		(drill 0.2032)
		(layers "F.Cu" "B.Cu")
		(net "GND")
	)
	(via
		(at 340.784434 -230.900478)
		(size 0.4572)
		(drill 0.2032)
		(layers "F.Cu" "B.Cu")
		(net "GND")
	)
	(via
		(at 346.063316 -269.38351)
		(size 0.4572)
		(drill 0.2032)
		(layers "F.Cu" "B.Cu")
		(net "GND")
	)
	(via
		(at 455.011282 -266.1666)
		(size 0.4572)
		(drill 0.2032)
		(layers "F.Cu" "B.Cu")
		(net "GND")
	)
	(via
		(at 82.580226 -333.529432)
		(size 0.508)
		(drill 0.254)
		(layers "F.Cu" "B.Cu")
		(net "GND")
	)
	(via
		(at 409.748482 -207.51673)
		(size 0.4572)
		(drill 0.2032)
		(layers "F.Cu" "B.Cu")
		(net "GND")
	)
	(via
		(at 31.592266 -17.61236)
		(size 0.508)
		(drill 0.254)
		(layers "F.Cu" "B.Cu")
		(net "GND")
	)
	(via
		(at 105.12679 -331.776832)
		(size 0.49022)
		(drill 0.254)
		(layers "F.Cu" "B.Cu")
		(net "GND")
	)
	(via
		(at 272.273014 -270.416782)
		(size 0.4572)
		(drill 0.2032)
		(layers "F.Cu" "B.Cu")
		(net "GND")
	)
	(via
		(at 347.002862 -282.405836)
		(size 0.4572)
		(drill 0.2032)
		(layers "F.Cu" "B.Cu")
		(net "GND")
	)
	(via
		(at 63.942214 -306.96662)
		(size 0.4572)
		(drill 0.2032)
		(layers "F.Cu" "B.Cu")
		(net "GND")
	)
	(via
		(at 159.779462 -404.51786)
		(size 0.4572)
		(drill 0.254)
		(layers "F.Cu" "B.Cu")
		(net "GND")
	)
	(via
		(at 63.250064 -438.651396)
		(size 0.4572)
		(drill 0.2032)
		(layers "F.Cu" "B.Cu")
		(net "GND")
	)
	(via
		(at 415.468562 -360.148378)
		(size 0.49022)
		(drill 0.254)
		(layers "F.Cu" "B.Cu")
		(net "GND")
	)
	(via
		(at 190.093346 -287.416748)
		(size 0.4572)
		(drill 0.2032)
		(layers "F.Cu" "B.Cu")
		(net "GND")
	)
	(via
		(at 94.723966 -245.55069)
		(size 0.4572)
		(drill 0.2032)
		(layers "F.Cu" "B.Cu")
		(net "GND")
	)
	(via
		(at 48.142906 -19.13636)
		(size 0.508)
		(drill 0.254)
		(layers "F.Cu" "B.Cu")
		(net "GND")
	)
	(via
		(at 287.360614 -313.766708)
		(size 0.4572)
		(drill 0.2032)
		(layers "F.Cu" "B.Cu")
		(net "GND")
	)
	(via
		(at 282.413964 -441.225432)
		(size 0.508)
		(drill 0.254)
		(layers "F.Cu" "B.Cu")
		(net "GND")
	)
	(via
		(at 186.649614 -299.316648)
		(size 0.4572)
		(drill 0.2032)
		(layers "F.Cu" "B.Cu")
		(net "GND")
	)
	(via
		(at 180.339746 -289.11677)
		(size 0.4572)
		(drill 0.2032)
		(layers "F.Cu" "B.Cu")
		(net "GND")
	)
	(via
		(at 361.227116 -331.776832)
		(size 0.49022)
		(drill 0.254)
		(layers "F.Cu" "B.Cu")
		(net "GND")
	)
	(via
		(at 417.292282 -299.316648)
		(size 0.4572)
		(drill 0.2032)
		(layers "F.Cu" "B.Cu")
		(net "GND")
	)
	(via
		(at 176.896014 -303.566576)
		(size 0.4572)
		(drill 0.2032)
		(layers "F.Cu" "B.Cu")
		(net "GND")
	)
	(via
		(at 358.864154 -50.207672)
		(size 0.49022)
		(drill 0.254)
		(layers "F.Cu" "B.Cu")
		(net "GND")
	)
	(via
		(at 372.377462 -287.28924)
		(size 0.4572)
		(drill 0.2032)
		(layers "F.Cu" "B.Cu")
		(net "GND")
	)
	(via
		(at 294.904414 -203.266802)
		(size 0.4572)
		(drill 0.2032)
		(layers "F.Cu" "B.Cu")
		(net "GND")
	)
	(via
		(at 169.352214 -295.916604)
		(size 0.4572)
		(drill 0.2032)
		(layers "F.Cu" "B.Cu")
		(net "GND")
	)
	(via
		(at 98.953066 -220.319854)
		(size 0.4572)
		(drill 0.2032)
		(layers "F.Cu" "B.Cu")
		(net "GND")
	)
	(via
		(at 391.102596 -16.967454)
		(size 0.508)
		(drill 0.254)
		(layers "F.Cu" "B.Cu")
		(net "GND")
	)
	(via
		(at 136.655048 -257.98907)
		(size 0.4572)
		(drill 0.2032)
		(layers "F.Cu" "B.Cu")
		(net "GND")
	)
	(via
		(at 181.824884 -323.434456)
		(size 0.4572)
		(drill 0.2032)
		(layers "F.Cu" "B.Cu")
		(net "GND")
	)
	(via
		(at 140.349986 -427.699678)
		(size 0.4572)
		(drill 0.2032)
		(layers "F.Cu" "B.Cu")
		(net "GND")
	)
	(via
		(at 145.448274 -407.00452)
		(size 0.4064)
		(drill 0.2032)
		(layers "F.Cu" "B.Cu")
		(net "GND")
	)
	(via
		(at 283.916882 -286.56661)
		(size 0.4572)
		(drill 0.2032)
		(layers "F.Cu" "B.Cu")
		(net "GND")
	)
	(via
		(at 359.752392 -334.282034)
		(size 0.49022)
		(drill 0.254)
		(layers "F.Cu" "B.Cu")
		(net "GND")
	)
	(via
		(at 256.750312 -77.424788)
		(size 0.508)
		(drill 0.254)
		(layers "F.Cu" "B.Cu")
		(net "GND")
	)
	(via
		(at 63.942214 -249.166634)
		(size 0.4572)
		(drill 0.2032)
		(layers "F.Cu" "B.Cu")
		(net "GND")
	)
	(via
		(at 426.595032 -397.09852)
		(size 0.508)
		(drill 0.254)
		(layers "F.Cu" "B.Cu")
		(net "GND")
	)
	(via
		(at 62.267846 -311.216802)
		(size 0.4572)
		(drill 0.2032)
		(layers "F.Cu" "B.Cu")
		(net "GND")
	)
	(via
		(at 86.265766 -232.528364)
		(size 0.4572)
		(drill 0.2032)
		(layers "F.Cu" "B.Cu")
		(net "GND")
	)
	(via
		(at 66.152014 -222.816674)
		(size 0.4572)
		(drill 0.2032)
		(layers "F.Cu" "B.Cu")
		(net "GND")
	)
	(via
		(at 432.379882 -241.516662)
		(size 0.4572)
		(drill 0.2032)
		(layers "F.Cu" "B.Cu")
		(net "GND")
	)
	(via
		(at 258.456938 -65.005712)
		(size 0.6604)
		(drill 0.3302)
		(layers "F.Cu" "B.Cu")
		(net "GND")
	)
	(via
		(at 355.821234 -222.761556)
		(size 0.4572)
		(drill 0.2032)
		(layers "F.Cu" "B.Cu")
		(net "GND")
	)
	(via
		(at 157.470856 -238.966756)
		(size 0.4572)
		(drill 0.2032)
		(layers "F.Cu" "B.Cu")
		(net "GND")
	)
	(via
		(at 133.820408 -129.878074)
		(size 0.508)
		(drill 0.254)
		(layers "F.Cu" "B.Cu")
		(net "GND")
	)
	(via
		(at 270.063214 -265.316716)
		(size 0.4572)
		(drill 0.2032)
		(layers "F.Cu" "B.Cu")
		(net "GND")
	)
	(via
		(at 460.664814 -272.116804)
		(size 0.4572)
		(drill 0.2032)
		(layers "F.Cu" "B.Cu")
		(net "GND")
	)
	(via
		(at 424.836082 -294.216582)
		(size 0.4572)
		(drill 0.2032)
		(layers "F.Cu" "B.Cu")
		(net "GND")
	)
	(via
		(at 180.339746 -268.71676)
		(size 0.4572)
		(drill 0.2032)
		(layers "F.Cu" "B.Cu")
		(net "GND")
	)
	(via
		(at 42.414444 -146.283172)
		(size 0.508)
		(drill 0.254)
		(layers "F.Cu" "B.Cu")
		(net "GND")
	)
	(via
		(at 430.489614 -242.3668)
		(size 0.4572)
		(drill 0.2032)
		(layers "F.Cu" "B.Cu")
		(net "GND")
	)
	(via
		(at 171.817792 -310.366664)
		(size 0.4572)
		(drill 0.2032)
		(layers "F.Cu" "B.Cu")
		(net "GND")
	)
	(via
		(at 337.965034 -222.761556)
		(size 0.4572)
		(drill 0.2032)
		(layers "F.Cu" "B.Cu")
		(net "GND")
	)
	(via
		(at 23.946866 -7.215124)
		(size 0.508)
		(drill 0.254)
		(layers "F.Cu" "B.Cu")
		(net "GND")
	)
	(via
		(at 80.25003 -429.147224)
		(size 0.4572)
		(drill 0.2032)
		(layers "F.Cu" "B.Cu")
		(net "GND")
	)
	(via
		(at 407.858214 -273.816572)
		(size 0.4572)
		(drill 0.2032)
		(layers "F.Cu" "B.Cu")
		(net "GND")
	)
	(via
		(at 424.836082 -249.166634)
		(size 0.4572)
		(drill 0.2032)
		(layers "F.Cu" "B.Cu")
		(net "GND")
	)
	(via
		(at 314.092082 -198.166736)
		(size 0.4572)
		(drill 0.2032)
		(layers "F.Cu" "B.Cu")
		(net "GND")
	)
	(via
		(at 424.936412 -16.967454)
		(size 0.508)
		(drill 0.254)
		(layers "F.Cu" "B.Cu")
		(net "GND")
	)
	(via
		(at 56.398414 -211.766658)
		(size 0.4572)
		(drill 0.2032)
		(layers "F.Cu" "B.Cu")
		(net "GND")
	)
	(via
		(at 302.448214 -272.116804)
		(size 0.4572)
		(drill 0.2032)
		(layers "F.Cu" "B.Cu")
		(net "GND")
	)
	(via
		(at 276.373082 -299.316648)
		(size 0.4572)
		(drill 0.2032)
		(layers "F.Cu" "B.Cu")
		(net "GND")
	)
	(via
		(at 13.345414 -289.966654)
		(size 0.4572)
		(drill 0.2032)
		(layers "F.Cu" "B.Cu")
		(net "GND")
	)
	(via
		(at 176.155604 -115.775486)
		(size 0.4572)
		(drill 0.254)
		(layers "F.Cu" "B.Cu")
		(net "GND")
	)
	(via
		(at 262.519414 -203.266802)
		(size 0.4572)
		(drill 0.2032)
		(layers "F.Cu" "B.Cu")
		(net "GND")
	)
	(via
		(at 179.105814 -303.566576)
		(size 0.4572)
		(drill 0.2032)
		(layers "F.Cu" "B.Cu")
		(net "GND")
	)
	(via
		(at 202.971146 -306.116736)
		(size 0.4572)
		(drill 0.2032)
		(layers "F.Cu" "B.Cu")
		(net "GND")
	)
	(via
		(at 51.830478 -410.030168)
		(size 0.4064)
		(drill 0.2032)
		(layers "F.Cu" "B.Cu")
		(net "GND")
	)
	(via
		(at 195.427346 -311.216802)
		(size 0.4572)
		(drill 0.2032)
		(layers "F.Cu" "B.Cu")
		(net "GND")
	)
	(via
		(at 120.438926 -123.112784)
		(size 0.508)
		(drill 0.254)
		(layers "F.Cu" "B.Cu")
		(net "GND")
	)
	(via
		(at 457.221082 -244.066568)
		(size 0.4572)
		(drill 0.2032)
		(layers "F.Cu" "B.Cu")
		(net "GND")
	)
	(via
		(at 357.609902 -295.038526)
		(size 0.508)
		(drill 0.254)
		(layers "F.Cu" "B.Cu")
		(net "GND")
	)
	(via
		(at 133.365494 -260.430772)
		(size 0.4572)
		(drill 0.2032)
		(layers "F.Cu" "B.Cu")
		(net "GND")
	)
	(via
		(at 63.942214 -305.266598)
		(size 0.4572)
		(drill 0.2032)
		(layers "F.Cu" "B.Cu")
		(net "GND")
	)
	(via
		(at 278.3586 -418.32149)
		(size 0.508)
		(drill 0.254)
		(layers "F.Cu" "B.Cu")
		(net "GND")
	)
	(via
		(at 261.285482 -241.516662)
		(size 0.4572)
		(drill 0.2032)
		(layers "F.Cu" "B.Cu")
		(net "GND")
	)
	(via
		(at 388.950708 -340.919816)
		(size 0.508)
		(drill 0.254)
		(layers "F.Cu" "B.Cu")
		(net "GND")
	)
	(via
		(at 58.608214 -275.516594)
		(size 0.4572)
		(drill 0.2032)
		(layers "F.Cu" "B.Cu")
		(net "GND")
	)
	(via
		(at 279.816814 -229.616762)
		(size 0.4572)
		(drill 0.2032)
		(layers "F.Cu" "B.Cu")
		(net "GND")
	)
	(via
		(at 43.520614 -215.166702)
		(size 0.4572)
		(drill 0.2032)
		(layers "F.Cu" "B.Cu")
		(net "GND")
	)
	(via
		(at 336.664808 -277.522686)
		(size 0.4572)
		(drill 0.2032)
		(layers "F.Cu" "B.Cu")
		(net "GND")
	)
	(via
		(at 453.025002 -69.461634)
		(size 0.508)
		(drill 0.254)
		(layers "F.Cu" "B.Cu")
		(net "GND")
	)
	(via
		(at 214.615014 -205.816708)
		(size 0.4572)
		(drill 0.2032)
		(layers "F.Cu" "B.Cu")
		(net "GND")
	)
	(via
		(at 414.070292 -162.217354)
		(size 0.49022)
		(drill 0.254)
		(layers "F.Cu" "B.Cu")
		(net "GND")
	)
	(via
		(at 392.667998 -400.224244)
		(size 0.4572)
		(drill 0.254)
		(layers "F.Cu" "B.Cu")
		(net "GND")
	)
	(via
		(at 432.379882 -233.86669)
		(size 0.4572)
		(drill 0.2032)
		(layers "F.Cu" "B.Cu")
		(net "GND")
	)
	(via
		(at 121.508266 -217.064336)
		(size 0.4572)
		(drill 0.2032)
		(layers "F.Cu" "B.Cu")
		(net "GND")
	)
	(via
		(at 279.816814 -240.666778)
		(size 0.4572)
		(drill 0.2032)
		(layers "F.Cu" "B.Cu")
		(net "GND")
	)
	(via
		(at 212.724746 -263.616694)
		(size 0.4572)
		(drill 0.2032)
		(layers "F.Cu" "B.Cu")
		(net "GND")
	)
	(via
		(at 201.737214 -294.216582)
		(size 0.4572)
		(drill 0.2032)
		(layers "F.Cu" "B.Cu")
		(net "GND")
	)
	(via
		(at 234.26928 -421.882062)
		(size 0.508)
		(drill 0.254)
		(layers "F.Cu" "B.Cu")
		(net "GND")
	)
	(via
		(at 175.005746 -216.016586)
		(size 0.4572)
		(drill 0.2032)
		(layers "F.Cu" "B.Cu")
		(net "GND")
	)
	(via
		(at 320.3575 -400.224244)
		(size 0.4572)
		(drill 0.254)
		(layers "F.Cu" "B.Cu")
		(net "GND")
	)
	(via
		(at 370.048028 -331.776832)
		(size 0.49022)
		(drill 0.254)
		(layers "F.Cu" "B.Cu")
		(net "GND")
	)
	(via
		(at 392.34999 -437.34736)
		(size 0.4572)
		(drill 0.2032)
		(layers "F.Cu" "B.Cu")
		(net "GND")
	)
	(via
		(at 165.252146 -315.46673)
		(size 0.4572)
		(drill 0.2032)
		(layers "F.Cu" "B.Cu")
		(net "GND")
	)
	(via
		(at 424.496484 -360.937556)
		(size 0.49022)
		(drill 0.254)
		(layers "F.Cu" "B.Cu")
		(net "GND")
	)
	(via
		(at 270.063214 -231.316784)
		(size 0.4572)
		(drill 0.2032)
		(layers "F.Cu" "B.Cu")
		(net "GND")
	)
	(via
		(at 337.604862 -269.38351)
		(size 0.4572)
		(drill 0.2032)
		(layers "F.Cu" "B.Cu")
		(net "GND")
	)
	(via
		(at 35.976814 -221.116652)
		(size 0.4572)
		(drill 0.2032)
		(layers "F.Cu" "B.Cu")
		(net "GND")
	)
	(via
		(at 202.971146 -217.716608)
		(size 0.4572)
		(drill 0.2032)
		(layers "F.Cu" "B.Cu")
		(net "GND")
	)
	(via
		(at 342.924892 -331.776832)
		(size 0.49022)
		(drill 0.254)
		(layers "F.Cu" "B.Cu")
		(net "GND")
	)
	(via
		(at 314.092082 -275.516594)
		(size 0.4572)
		(drill 0.2032)
		(layers "F.Cu" "B.Cu")
		(net "GND")
	)
	(via
		(at 409.69692 -167.071548)
		(size 0.508)
		(drill 0.254)
		(layers "F.Cu" "B.Cu")
		(net "GND")
	)
	(via
		(at 201.737214 -230.466646)
		(size 0.4572)
		(drill 0.2032)
		(layers "F.Cu" "B.Cu")
		(net "GND")
	)
	(via
		(at 11.135614 -299.316648)
		(size 0.4572)
		(drill 0.2032)
		(layers "F.Cu" "B.Cu")
		(net "GND")
	)
	(via
		(at 349.822262 -272.639282)
		(size 0.4572)
		(drill 0.2032)
		(layers "F.Cu" "B.Cu")
		(net "GND")
	)
	(via
		(at 113.519966 -230.900478)
		(size 0.4572)
		(drill 0.2032)
		(layers "F.Cu" "B.Cu")
		(net "GND")
	)
	(via
		(at 90.134694 -281.59202)
		(size 0.4572)
		(drill 0.2032)
		(layers "F.Cu" "B.Cu")
		(net "GND")
	)
	(via
		(at 370.85778 -248.806208)
		(size 0.4572)
		(drill 0.2032)
		(layers "F.Cu" "B.Cu")
		(net "GND")
	)
	(via
		(at 135.787638 -340.977728)
		(size 0.49022)
		(drill 0.254)
		(layers "F.Cu" "B.Cu")
		(net "GND")
	)
	(via
		(at 12.9286 -426.15485)
		(size 0.508)
		(drill 0.254)
		(layers "F.Cu" "B.Cu")
		(net "GND")
	)
	(via
		(at 292.694614 -315.46673)
		(size 0.4572)
		(drill 0.2032)
		(layers "F.Cu" "B.Cu")
		(net "GND")
	)
	(via
		(at 129.136394 -287.28924)
		(size 0.4572)
		(drill 0.2032)
		(layers "F.Cu" "B.Cu")
		(net "GND")
	)
	(via
		(at 184.439814 -295.916604)
		(size 0.4572)
		(drill 0.2032)
		(layers "F.Cu" "B.Cu")
		(net "GND")
	)
	(via
		(at 450.911214 -258.516628)
		(size 0.4572)
		(drill 0.2032)
		(layers "F.Cu" "B.Cu")
		(net "GND")
	)
	(via
		(at 94.833948 -278.336502)
		(size 0.4572)
		(drill 0.2032)
		(layers "F.Cu" "B.Cu")
		(net "GND")
	)
	(via
		(at 186.649614 -210.066636)
		(size 0.4572)
		(drill 0.2032)
		(layers "F.Cu" "B.Cu")
		(net "GND")
	)
	(via
		(at 167.461946 -292.516814)
		(size 0.4572)
		(drill 0.2032)
		(layers "F.Cu" "B.Cu")
		(net "GND")
	)
	(via
		(at 111.306102 -331.776832)
		(size 0.49022)
		(drill 0.254)
		(layers "F.Cu" "B.Cu")
		(net "GND")
	)
	(via
		(at 450.307202 -78.861412)
		(size 0.508)
		(drill 0.254)
		(layers "F.Cu" "B.Cu")
		(net "GND")
	)
	(via
		(at 439.923682 -235.566712)
		(size 0.4572)
		(drill 0.2032)
		(layers "F.Cu" "B.Cu")
		(net "GND")
	)
	(via
		(at 265.424412 -69.91985)
		(size 0.6604)
		(drill 0.3302)
		(layers "F.Cu" "B.Cu")
		(net "GND")
	)
	(via
		(at 67.250056 -432.747166)
		(size 0.4572)
		(drill 0.2032)
		(layers "F.Cu" "B.Cu")
		(net "GND")
	)
	(via
		(at 209.281014 -286.56661)
		(size 0.4572)
		(drill 0.2032)
		(layers "F.Cu" "B.Cu")
		(net "GND")
	)
	(via
		(at 43.520614 -267.866622)
		(size 0.4572)
		(drill 0.2032)
		(layers "F.Cu" "B.Cu")
		(net "GND")
	)
	(via
		(at 134.305548 -284.847538)
		(size 0.4572)
		(drill 0.2032)
		(layers "F.Cu" "B.Cu")
		(net "GND")
	)
	(via
		(at 299.004482 -310.366664)
		(size 0.4572)
		(drill 0.2032)
		(layers "F.Cu" "B.Cu")
		(net "GND")
	)
	(via
		(at 453.121014 -201.56678)
		(size 0.4572)
		(drill 0.2032)
		(layers "F.Cu" "B.Cu")
		(net "GND")
	)
	(via
		(at 302.733964 -441.225432)
		(size 0.508)
		(drill 0.254)
		(layers "F.Cu" "B.Cu")
		(net "GND")
	)
	(via
		(at 113.349532 -366.167924)
		(size 0.508)
		(drill 0.254)
		(layers "F.Cu" "B.Cu")
		(net "GND")
	)
	(via
		(at 357.717344 -329.722226)
		(size 0.508)
		(drill 0.254)
		(layers "F.Cu" "B.Cu")
		(net "GND")
	)
	(via
		(at 447.467482 -233.86669)
		(size 0.4572)
		(drill 0.2032)
		(layers "F.Cu" "B.Cu")
		(net "GND")
	)
	(via
		(at 306.548282 -261.066788)
		(size 0.4572)
		(drill 0.2032)
		(layers "F.Cu" "B.Cu")
		(net "GND")
	)
	(via
		(at 407.446988 -10.16508)
		(size 0.508)
		(drill 0.254)
		(layers "F.Cu" "B.Cu")
		(net "GND")
	)
	(via
		(at 78.250034 -438.499758)
		(size 0.4572)
		(drill 0.2032)
		(layers "F.Cu" "B.Cu")
		(net "GND")
	)
	(via
		(at 196.201284 -323.434456)
		(size 0.4572)
		(drill 0.2032)
		(layers "F.Cu" "B.Cu")
		(net "GND")
	)
	(via
		(at 90.25001 -433.747164)
		(size 0.4572)
		(drill 0.2032)
		(layers "F.Cu" "B.Cu")
		(net "GND")
	)
	(via
		(at 176.896014 -244.066568)
		(size 0.4572)
		(drill 0.2032)
		(layers "F.Cu" "B.Cu")
		(net "GND")
	)
	(via
		(at 336.665062 -267.755878)
		(size 0.4572)
		(drill 0.2032)
		(layers "F.Cu" "B.Cu")
		(net "GND")
	)
	(via
		(at 87.675466 -247.992138)
		(size 0.4572)
		(drill 0.2032)
		(layers "F.Cu" "B.Cu")
		(net "GND")
	)
	(via
		(at 367.678462 -284.033722)
		(size 0.4572)
		(drill 0.2032)
		(layers "F.Cu" "B.Cu")
		(net "GND")
	)
	(via
		(at 457.221082 -288.266632)
		(size 0.4572)
		(drill 0.2032)
		(layers "F.Cu" "B.Cu")
		(net "GND")
	)
	(via
		(at 335.14538 -237.411768)
		(size 0.4572)
		(drill 0.2032)
		(layers "F.Cu" "B.Cu")
		(net "GND")
	)
	(via
		(at 9.245346 -263.616694)
		(size 0.4572)
		(drill 0.2032)
		(layers "F.Cu" "B.Cu")
		(net "GND")
	)
	(via
		(at 179.105814 -286.56661)
		(size 0.4572)
		(drill 0.2032)
		(layers "F.Cu" "B.Cu")
		(net "GND")
	)
	(via
		(at 375.557034 -234.15625)
		(size 0.4572)
		(drill 0.2032)
		(layers "F.Cu" "B.Cu")
		(net "GND")
	)
	(via
		(at 13.345414 -317.166752)
		(size 0.4572)
		(drill 0.2032)
		(layers "F.Cu" "B.Cu")
		(net "GND")
	)
	(via
		(at 63.942214 -250.866656)
		(size 0.4572)
		(drill 0.2032)
		(layers "F.Cu" "B.Cu")
		(net "GND")
	)
	(via
		(at 167.461946 -210.916774)
		(size 0.4572)
		(drill 0.2032)
		(layers "F.Cu" "B.Cu")
		(net "GND")
	)
	(via
		(at 29.666946 -279.766776)
		(size 0.4572)
		(drill 0.2032)
		(layers "F.Cu" "B.Cu")
		(net "GND")
	)
	(via
		(at 142.385034 -410.030168)
		(size 0.4064)
		(drill 0.2032)
		(layers "F.Cu" "B.Cu")
		(net "GND")
	)
	(via
		(at 344.25001 -429.147224)
		(size 0.4572)
		(drill 0.2032)
		(layers "F.Cu" "B.Cu")
		(net "GND")
	)
	(via
		(at 389.146542 -410.664152)
		(size 0.4572)
		(drill 0.254)
		(layers "F.Cu" "B.Cu")
		(net "GND")
	)
	(via
		(at 48.638714 -275.516594)
		(size 0.4572)
		(drill 0.2032)
		(layers "F.Cu" "B.Cu")
		(net "GND")
	)
	(via
		(at 412.956756 -9.424924)
		(size 0.508)
		(drill 0.254)
		(layers "F.Cu" "B.Cu")
		(net "GND")
	)
	(via
		(at 43.006772 -351.608644)
		(size 0.49022)
		(drill 0.254)
		(layers "F.Cu" "B.Cu")
		(net "GND")
	)
	(via
		(at 97.543112 -230.900478)
		(size 0.4572)
		(drill 0.2032)
		(layers "F.Cu" "B.Cu")
		(net "GND")
	)
	(via
		(at 373.787162 -276.708616)
		(size 0.4572)
		(drill 0.2032)
		(layers "F.Cu" "B.Cu")
		(net "GND")
	)
	(via
		(at 427.045882 -196.466714)
		(size 0.4572)
		(drill 0.2032)
		(layers "F.Cu" "B.Cu")
		(net "GND")
	)
	(via
		(at 101.617018 -329.061826)
		(size 0.508)
		(drill 0.254)
		(layers "F.Cu" "B.Cu")
		(net "GND")
	)
	(via
		(at 159.779462 -400.224244)
		(size 0.4572)
		(drill 0.254)
		(layers "F.Cu" "B.Cu")
		(net "GND")
	)
	(via
		(at 47.811182 -352.304858)
		(size 0.508)
		(drill 0.254)
		(layers "F.Cu" "B.Cu")
		(net "GND")
	)
	(via
		(at 20.889214 -211.766658)
		(size 0.4572)
		(drill 0.2032)
		(layers "F.Cu" "B.Cu")
		(net "GND")
	)
	(via
		(at 329.25004 -434.899562)
		(size 0.4572)
		(drill 0.2032)
		(layers "F.Cu" "B.Cu")
		(net "GND")
	)
	(via
		(at 372.377462 -269.38351)
		(size 0.4572)
		(drill 0.2032)
		(layers "F.Cu" "B.Cu")
		(net "GND")
	)
	(via
		(at 208.71688 -108.822998)
		(size 0.508)
		(drill 0.254)
		(layers "F.Cu" "B.Cu")
		(net "GND")
	)
	(via
		(at 435.823614 -283.166566)
		(size 0.4572)
		(drill 0.2032)
		(layers "F.Cu" "B.Cu")
		(net "GND")
	)
	(via
		(at 378.376434 -226.017328)
		(size 0.4572)
		(drill 0.2032)
		(layers "F.Cu" "B.Cu")
		(net "GND")
	)
	(via
		(at 129.136394 -274.266914)
		(size 0.4572)
		(drill 0.2032)
		(layers "F.Cu" "B.Cu")
		(net "GND")
	)
	(via
		(at 297.88993 -56.432196)
		(size 0.508)
		(drill 0.254)
		(layers "F.Cu" "B.Cu")
		(net "GND")
	)
	(via
		(at 14.579346 -273.816572)
		(size 0.4572)
		(drill 0.2032)
		(layers "F.Cu" "B.Cu")
		(net "GND")
	)
	(via
		(at 418.520118 -406.370536)
		(size 0.4572)
		(drill 0.254)
		(layers "F.Cu" "B.Cu")
		(net "GND")
	)
	(via
		(at 52.298346 -261.916672)
		(size 0.4572)
		(drill 0.2032)
		(layers "F.Cu" "B.Cu")
		(net "GND")
	)
	(via
		(at 167.461946 -250.016772)
		(size 0.4572)
		(drill 0.2032)
		(layers "F.Cu" "B.Cu")
		(net "GND")
	)
	(via
		(at 140.706602 -339.170772)
		(size 0.508)
		(drill 0.254)
		(layers "F.Cu" "B.Cu")
		(net "GND")
	)
	(via
		(at 464.764882 -233.86669)
		(size 0.4572)
		(drill 0.2032)
		(layers "F.Cu" "B.Cu")
		(net "GND")
	)
	(via
		(at 467.535514 -114.16538)
		(size 0.508)
		(drill 0.254)
		(layers "F.Cu" "B.Cu")
		(net "GND")
	)
	(via
		(at 44.13377 -5.596636)
		(size 0.508)
		(drill 0.254)
		(layers "F.Cu" "B.Cu")
		(net "GND")
	)
	(via
		(at 156.355288 -44.181268)
		(size 0.508)
		(drill 0.254)
		(layers "F.Cu" "B.Cu")
		(net "GND")
	)
	(via
		(at 291.460682 -289.966654)
		(size 0.4572)
		(drill 0.2032)
		(layers "F.Cu" "B.Cu")
		(net "GND")
	)
	(via
		(at 35.976814 -284.866588)
		(size 0.4572)
		(drill 0.2032)
		(layers "F.Cu" "B.Cu")
		(net "GND")
	)
	(via
		(at 412.18358 -159.095948)
		(size 0.508)
		(drill 0.254)
		(layers "F.Cu" "B.Cu")
		(net "GND")
	)
	(via
		(at 439.923682 -299.316648)
		(size 0.4572)
		(drill 0.2032)
		(layers "F.Cu" "B.Cu")
		(net "GND")
	)
	(via
		(at 40.256968 -9.424924)
		(size 0.508)
		(drill 0.254)
		(layers "F.Cu" "B.Cu")
		(net "GND")
	)
	(via
		(at 161.808414 -232.166668)
		(size 0.4572)
		(drill 0.2032)
		(layers "F.Cu" "B.Cu")
		(net "GND")
	)
	(via
		(at 167.665146 -273.816572)
		(size 0.4572)
		(drill 0.2032)
		(layers "F.Cu" "B.Cu")
		(net "GND")
	)
	(via
		(at 117.389148 -271.825212)
		(size 0.4572)
		(drill 0.2032)
		(layers "F.Cu" "B.Cu")
		(net "GND")
	)
	(via
		(at 457.221082 -247.466612)
		(size 0.4572)
		(drill 0.2032)
		(layers "F.Cu" "B.Cu")
		(net "GND")
	)
	(via
		(at 233.92892 -127.861822)
		(size 0.508)
		(drill 0.254)
		(layers "F.Cu" "B.Cu")
		(net "GND")
	)
	(via
		(at 314.092082 -200.716642)
		(size 0.4572)
		(drill 0.2032)
		(layers "F.Cu" "B.Cu")
		(net "GND")
	)
	(via
		(at 415.648648 -180.098954)
		(size 0.49022)
		(drill 0.254)
		(layers "F.Cu" "B.Cu")
		(net "GND")
	)
	(via
		(at 149.67204 -131.932934)
		(size 0.508)
		(drill 0.254)
		(layers "F.Cu" "B.Cu")
		(net "GND")
	)
	(via
		(at 379.895862 -282.405836)
		(size 0.4572)
		(drill 0.2032)
		(layers "F.Cu" "B.Cu")
		(net "GND")
	)
	(via
		(at 214.32774 -115.143788)
		(size 0.508)
		(drill 0.254)
		(layers "F.Cu" "B.Cu")
		(net "GND")
	)
	(via
		(at 314.307982 -271.266666)
		(size 0.4572)
		(drill 0.2032)
		(layers "F.Cu" "B.Cu")
		(net "GND")
	)
	(via
		(at 366.372902 -242.960906)
		(size 0.4572)
		(drill 0.2032)
		(layers "F.Cu" "B.Cu")
		(net "GND")
	)
	(via
		(at 422.945814 -296.766742)
		(size 0.4572)
		(drill 0.2032)
		(layers "F.Cu" "B.Cu")
		(net "GND")
	)
	(via
		(at 457.221082 -261.066788)
		(size 0.4572)
		(drill 0.2032)
		(layers "F.Cu" "B.Cu")
		(net "GND")
	)
	(via
		(at 276.373082 -289.966654)
		(size 0.4572)
		(drill 0.2032)
		(layers "F.Cu" "B.Cu")
		(net "GND")
	)
	(via
		(at 240.50371 -247.415558)
		(size 0.508)
		(drill 0.254)
		(layers "F.Cu" "B.Cu")
		(net "GND")
	)
	(via
		(at 374.038368 -333.13243)
		(size 0.508)
		(drill 0.254)
		(layers "F.Cu" "B.Cu")
		(net "GND")
	)
	(via
		(at 162.745674 -410.030168)
		(size 0.4064)
		(drill 0.2032)
		(layers "F.Cu" "B.Cu")
		(net "GND")
	)
	(via
		(at 355.821234 -226.017328)
		(size 0.4572)
		(drill 0.2032)
		(layers "F.Cu" "B.Cu")
		(net "GND")
	)
	(via
		(at 216.943178 -23.172928)
		(size 0.508)
		(drill 0.254)
		(layers "F.Cu" "B.Cu")
		(net "GND")
	)
	(via
		(at 323.42074 -404.51786)
		(size 0.4572)
		(drill 0.254)
		(layers "F.Cu" "B.Cu")
		(net "GND")
	)
	(via
		(at 201.737214 -305.266598)
		(size 0.4572)
		(drill 0.2032)
		(layers "F.Cu" "B.Cu")
		(net "GND")
	)
	(via
		(at 268.829282 -200.716642)
		(size 0.4572)
		(drill 0.2032)
		(layers "F.Cu" "B.Cu")
		(net "GND")
	)
	(via
		(at 363.25302 -65.872868)
		(size 0.508)
		(drill 0.254)
		(layers "F.Cu" "B.Cu")
		(net "GND")
	)
	(via
		(at 442.133482 -261.066788)
		(size 0.4572)
		(drill 0.2032)
		(layers "F.Cu" "B.Cu")
		(net "GND")
	)
	(via
		(at 136.532366 -403.249892)
		(size 0.4572)
		(drill 0.254)
		(layers "F.Cu" "B.Cu")
		(net "GND")
	)
	(via
		(at 124.437394 -261.244842)
		(size 0.4572)
		(drill 0.2032)
		(layers "F.Cu" "B.Cu")
		(net "GND")
	)
	(via
		(at 145.349976 -434.899562)
		(size 0.4572)
		(drill 0.2032)
		(layers "F.Cu" "B.Cu")
		(net "GND")
	)
	(via
		(at 26.496772 -412.08452)
		(size 0.508)
		(drill 0.254)
		(layers "F.Cu" "B.Cu")
		(net "GND")
	)
	(via
		(at 285.150814 -287.416748)
		(size 0.4572)
		(drill 0.2032)
		(layers "F.Cu" "B.Cu")
		(net "GND")
	)
	(via
		(at 299.004482 -312.91657)
		(size 0.4572)
		(drill 0.2032)
		(layers "F.Cu" "B.Cu")
		(net "GND")
	)
	(via
		(at 181.407308 -43.918886)
		(size 0.508)
		(drill 0.254)
		(layers "F.Cu" "B.Cu")
		(net "GND")
	)
	(via
		(at 28.638246 -387.246876)
		(size 0.508)
		(drill 0.254)
		(layers "F.Cu" "B.Cu")
		(net "GND")
	)
	(via
		(at 388.003034 -248.680478)
		(size 0.4572)
		(drill 0.2032)
		(layers "F.Cu" "B.Cu")
		(net "GND")
	)
	(via
		(at 99.422966 -235.783882)
		(size 0.4572)
		(drill 0.2032)
		(layers "F.Cu" "B.Cu")
		(net "GND")
	)
	(via
		(at 143.495776 -64.051942)
		(size 0.508)
		(drill 0.254)
		(layers "F.Cu" "B.Cu")
		(net "GND")
	)
	(via
		(at 384.350006 -438.499758)
		(size 0.4572)
		(drill 0.2032)
		(layers "F.Cu" "B.Cu")
		(net "GND")
	)
	(via
		(at 413.336486 -182.999126)
		(size 0.508)
		(drill 0.254)
		(layers "F.Cu" "B.Cu")
		(net "GND")
	)
	(via
		(at 424.836082 -202.416664)
		(size 0.4572)
		(drill 0.2032)
		(layers "F.Cu" "B.Cu")
		(net "GND")
	)
	(via
		(at 187.883546 -250.016772)
		(size 0.4572)
		(drill 0.2032)
		(layers "F.Cu" "B.Cu")
		(net "GND")
	)
	(via
		(at 55.254906 -407.638504)
		(size 0.4572)
		(drill 0.254)
		(layers "F.Cu" "B.Cu")
		(net "GND")
	)
	(via
		(at 351.701862 -284.033722)
		(size 0.4572)
		(drill 0.2032)
		(layers "F.Cu" "B.Cu")
		(net "GND")
	)
	(via
		(at 136.184894 -266.941808)
		(size 0.4572)
		(drill 0.2032)
		(layers "F.Cu" "B.Cu")
		(net "GND")
	)
	(via
		(at 270.063214 -313.766708)
		(size 0.4572)
		(drill 0.2032)
		(layers "F.Cu" "B.Cu")
		(net "GND")
	)
	(via
		(at 414.495488 -6.07949)
		(size 0.508)
		(drill 0.254)
		(layers "F.Cu" "B.Cu")
		(net "GND")
	)
	(via
		(at 438.033414 -242.3668)
		(size 0.4572)
		(drill 0.2032)
		(layers "F.Cu" "B.Cu")
		(net "GND")
	)
	(via
		(at 311.882282 -288.266632)
		(size 0.4572)
		(drill 0.2032)
		(layers "F.Cu" "B.Cu")
		(net "GND")
	)
	(via
		(at 165.252146 -229.616762)
		(size 0.4572)
		(drill 0.2032)
		(layers "F.Cu" "B.Cu")
		(net "GND")
	)
	(via
		(at 308.465728 -400.858228)
		(size 0.4064)
		(drill 0.2032)
		(layers "F.Cu" "B.Cu")
		(net "GND")
	)
	(via
		(at 430.489614 -267.016738)
		(size 0.4572)
		(drill 0.2032)
		(layers "F.Cu" "B.Cu")
		(net "GND")
	)
	(via
		(at 407.62301 -400.858228)
		(size 0.4064)
		(drill 0.2032)
		(layers "F.Cu" "B.Cu")
		(net "GND")
	)
	(via
		(at 159.918146 -273.816572)
		(size 0.4572)
		(drill 0.2032)
		(layers "F.Cu" "B.Cu")
		(net "GND")
	)
	(via
		(at 214.615014 -224.516696)
		(size 0.4572)
		(drill 0.2032)
		(layers "F.Cu" "B.Cu")
		(net "GND")
	)
	(via
		(at 435.823614 -250.016772)
		(size 0.4572)
		(drill 0.2032)
		(layers "F.Cu" "B.Cu")
		(net "GND")
	)
	(via
		(at 104.231948 -271.825212)
		(size 0.4572)
		(drill 0.2032)
		(layers "F.Cu" "B.Cu")
		(net "GND")
	)
	(via
		(at 375.634758 -409.396184)
		(size 0.4572)
		(drill 0.254)
		(layers "F.Cu" "B.Cu")
		(net "GND")
	)
	(via
		(at 180.339746 -212.616796)
		(size 0.4572)
		(drill 0.2032)
		(layers "F.Cu" "B.Cu")
		(net "GND")
	)
	(via
		(at 264.729214 -313.766708)
		(size 0.4572)
		(drill 0.2032)
		(layers "F.Cu" "B.Cu")
		(net "GND")
	)
	(via
		(at 217.001852 -72.015858)
		(size 0.508)
		(drill 0.254)
		(layers "F.Cu" "B.Cu")
		(net "GND")
	)
	(via
		(at 20.623784 -4.328668)
		(size 0.508)
		(drill 0.254)
		(layers "F.Cu" "B.Cu")
		(net "GND")
	)
	(via
		(at 127.726948 -258.80314)
		(size 0.4572)
		(drill 0.2032)
		(layers "F.Cu" "B.Cu")
		(net "GND")
	)
	(via
		(at 159.918146 -233.016806)
		(size 0.4572)
		(drill 0.2032)
		(layers "F.Cu" "B.Cu")
		(net "GND")
	)
	(via
		(at 39.420546 -307.816758)
		(size 0.4572)
		(drill 0.2032)
		(layers "F.Cu" "B.Cu")
		(net "GND")
	)
	(via
		(at 383.38125 -407.00452)
		(size 0.4064)
		(drill 0.2032)
		(layers "F.Cu" "B.Cu")
		(net "GND")
	)
	(via
		(at 31.876746 -278.066754)
		(size 0.4572)
		(drill 0.2032)
		(layers "F.Cu" "B.Cu")
		(net "GND")
	)
	(via
		(at 55.16753 -404.51786)
		(size 0.4572)
		(drill 0.254)
		(layers "F.Cu" "B.Cu")
		(net "GND")
	)
	(via
		(at 445.577214 -283.166566)
		(size 0.4572)
		(drill 0.2032)
		(layers "F.Cu" "B.Cu")
		(net "GND")
	)
	(via
		(at 344.86342 -400.224244)
		(size 0.4572)
		(drill 0.254)
		(layers "F.Cu" "B.Cu")
		(net "GND")
	)
	(via
		(at 106.471212 -231.714548)
		(size 0.4572)
		(drill 0.2032)
		(layers "F.Cu" "B.Cu")
		(net "GND")
	)
	(via
		(at 447.467482 -266.1666)
		(size 0.4572)
		(drill 0.2032)
		(layers "F.Cu" "B.Cu")
		(net "GND")
	)
	(via
		(at 86.250018 -434.899562)
		(size 0.4572)
		(drill 0.2032)
		(layers "F.Cu" "B.Cu")
		(net "GND")
	)
	(via
		(at 401.349972 -436.051198)
		(size 0.4572)
		(drill 0.2032)
		(layers "F.Cu" "B.Cu")
		(net "GND")
	)
	(via
		(at 457.221082 -310.366664)
		(size 0.4572)
		(drill 0.2032)
		(layers "F.Cu" "B.Cu")
		(net "GND")
	)
	(via
		(at 453.121014 -307.816758)
		(size 0.4572)
		(drill 0.2032)
		(layers "F.Cu" "B.Cu")
		(net "GND")
	)
	(via
		(at 323.508116 -409.396184)
		(size 0.4572)
		(drill 0.254)
		(layers "F.Cu" "B.Cu")
		(net "GND")
	)
	(via
		(at 411.047438 -403.249892)
		(size 0.4572)
		(drill 0.254)
		(layers "F.Cu" "B.Cu")
		(net "GND")
	)
	(via
		(at 298.895008 -354.868226)
		(size 0.508)
		(drill 0.254)
		(layers "F.Cu" "B.Cu")
		(net "GND")
	)
	(via
		(at 285.150814 -250.016772)
		(size 0.4572)
		(drill 0.2032)
		(layers "F.Cu" "B.Cu")
		(net "GND")
	)
	(via
		(at 413.349948 -439.651394)
		(size 0.4572)
		(drill 0.2032)
		(layers "F.Cu" "B.Cu")
		(net "GND")
	)
	(via
		(at 296.794682 -216.866724)
		(size 0.4572)
		(drill 0.2032)
		(layers "F.Cu" "B.Cu")
		(net "GND")
	)
	(via
		(at 363.339634 -219.506038)
		(size 0.4572)
		(drill 0.2032)
		(layers "F.Cu" "B.Cu")
		(net "GND")
	)
	(via
		(at 135.605266 -241.481102)
		(size 0.4572)
		(drill 0.2032)
		(layers "F.Cu" "B.Cu")
		(net "GND")
	)
	(via
		(at 187.883546 -214.316564)
		(size 0.4572)
		(drill 0.2032)
		(layers "F.Cu" "B.Cu")
		(net "GND")
	)
	(via
		(at 207.071214 -308.666642)
		(size 0.4572)
		(drill 0.2032)
		(layers "F.Cu" "B.Cu")
		(net "GND")
	)
	(via
		(at 264.729214 -311.216802)
		(size 0.4572)
		(drill 0.2032)
		(layers "F.Cu" "B.Cu")
		(net "GND")
	)
	(via
		(at 169.352214 -222.816674)
		(size 0.4572)
		(drill 0.2032)
		(layers "F.Cu" "B.Cu")
		(net "GND")
	)
	(via
		(at 447.467482 -286.56661)
		(size 0.4572)
		(drill 0.2032)
		(layers "F.Cu" "B.Cu")
		(net "GND")
	)
	(via
		(at 314.092082 -295.916604)
		(size 0.4572)
		(drill 0.2032)
		(layers "F.Cu" "B.Cu")
		(net "GND")
	)
	(via
		(at 149.349968 -436.051198)
		(size 0.4572)
		(drill 0.2032)
		(layers "F.Cu" "B.Cu")
		(net "GND")
	)
	(via
		(at 327.770744 -344.965274)
		(size 0.49022)
		(drill 0.254)
		(layers "F.Cu" "B.Cu")
		(net "GND")
	)
	(via
		(at 117.075458 -330.55052)
		(size 0.508)
		(drill 0.254)
		(layers "F.Cu" "B.Cu")
		(net "GND")
	)
	(via
		(at 172.795946 -263.616694)
		(size 0.4572)
		(drill 0.2032)
		(layers "F.Cu" "B.Cu")
		(net "GND")
	)
	(via
		(at 439.923682 -288.266632)
		(size 0.4572)
		(drill 0.2032)
		(layers "F.Cu" "B.Cu")
		(net "GND")
	)
	(via
		(at 9.245346 -306.116736)
		(size 0.4572)
		(drill 0.2032)
		(layers "F.Cu" "B.Cu")
		(net "GND")
	)
	(via
		(at 448.01282 -378.658628)
		(size 0.49022)
		(drill 0.254)
		(layers "F.Cu" "B.Cu")
		(net "GND")
	)
	(via
		(at 374.617234 -219.506038)
		(size 0.4572)
		(drill 0.2032)
		(layers "F.Cu" "B.Cu")
		(net "GND")
	)
	(via
		(at 54.724046 -273.816572)
		(size 0.4572)
		(drill 0.2032)
		(layers "F.Cu" "B.Cu")
		(net "GND")
	)
	(via
		(at 171.562014 -316.316614)
		(size 0.4572)
		(drill 0.2032)
		(layers "F.Cu" "B.Cu")
		(net "GND")
	)
	(via
		(at 50.996596 -354.109528)
		(size 0.49022)
		(drill 0.254)
		(layers "F.Cu" "B.Cu")
		(net "GND")
	)
	(via
		(at 187.883546 -234.716574)
		(size 0.4572)
		(drill 0.2032)
		(layers "F.Cu" "B.Cu")
		(net "GND")
	)
	(via
		(at 7.035546 -307.816758)
		(size 0.4572)
		(drill 0.2032)
		(layers "F.Cu" "B.Cu")
		(net "GND")
	)
	(via
		(at 261.285482 -232.166668)
		(size 0.4572)
		(drill 0.2032)
		(layers "F.Cu" "B.Cu")
		(net "GND")
	)
	(via
		(at 37.210746 -268.71676)
		(size 0.4572)
		(drill 0.2032)
		(layers "F.Cu" "B.Cu")
		(net "GND")
	)
	(via
		(at 339.391498 -191.93129)
		(size 0.508)
		(drill 0.254)
		(layers "F.Cu" "B.Cu")
		(net "GND")
	)
	(via
		(at 31.876746 -204.96657)
		(size 0.4572)
		(drill 0.2032)
		(layers "F.Cu" "B.Cu")
		(net "GND")
	)
	(via
		(at 104.02189 -12.544552)
		(size 0.508)
		(drill 0.254)
		(layers "F.Cu" "B.Cu")
		(net "GND")
	)
	(via
		(at 139.989814 -340.981792)
		(size 0.49022)
		(drill 0.254)
		(layers "F.Cu" "B.Cu")
		(net "GND")
	)
	(via
		(at 118.043452 -338.60359)
		(size 0.508)
		(drill 0.254)
		(layers "F.Cu" "B.Cu")
		(net "GND")
	)
	(via
		(at 134.195566 -245.55069)
		(size 0.4572)
		(drill 0.2032)
		(layers "F.Cu" "B.Cu")
		(net "GND")
	)
	(via
		(at 189.1792 -422.86936)
		(size 0.508)
		(drill 0.254)
		(layers "F.Cu" "B.Cu")
		(net "GND")
	)
	(via
		(at 412.168848 -310.366664)
		(size 0.4572)
		(drill 0.2032)
		(layers "F.Cu" "B.Cu")
		(net "GND")
	)
	(via
		(at 455.011282 -230.466646)
		(size 0.4572)
		(drill 0.2032)
		(layers "F.Cu" "B.Cu")
		(net "GND")
	)
	(via
		(at 458.543406 -78.402434)
		(size 0.508)
		(drill 0.254)
		(layers "F.Cu" "B.Cu")
		(net "GND")
	)
	(via
		(at 291.460682 -250.866656)
		(size 0.4572)
		(drill 0.2032)
		(layers "F.Cu" "B.Cu")
		(net "GND")
	)
	(via
		(at 92.844366 -226.017328)
		(size 0.4572)
		(drill 0.2032)
		(layers "F.Cu" "B.Cu")
		(net "GND")
	)
	(via
		(at 123.2281 -412.735268)
		(size 0.508)
		(drill 0.254)
		(layers "F.Cu" "B.Cu")
		(net "GND")
	)
	(via
		(at 387.800342 -401.492212)
		(size 0.4572)
		(drill 0.254)
		(layers "F.Cu" "B.Cu")
		(net "GND")
	)
	(via
		(at 418.919914 -141.238478)
		(size 0.508)
		(drill 0.254)
		(layers "F.Cu" "B.Cu")
		(net "GND")
	)
	(via
		(at 161.090102 -319.704466)
		(size 0.4572)
		(drill 0.2032)
		(layers "F.Cu" "B.Cu")
		(net "GND")
	)
	(via
		(at 214.615014 -222.816674)
		(size 0.4572)
		(drill 0.2032)
		(layers "F.Cu" "B.Cu")
		(net "GND")
	)
	(via
		(at 87.675466 -243.108988)
		(size 0.4572)
		(drill 0.2032)
		(layers "F.Cu" "B.Cu")
		(net "GND")
	)
	(via
		(at 97.183448 -257.98907)
		(size 0.4572)
		(drill 0.2032)
		(layers "F.Cu" "B.Cu")
		(net "GND")
	)
	(via
		(at 202.971146 -227.066602)
		(size 0.4572)
		(drill 0.2032)
		(layers "F.Cu" "B.Cu")
		(net "GND")
	)
	(via
		(at 209.281014 -210.066636)
		(size 0.4572)
		(drill 0.2032)
		(layers "F.Cu" "B.Cu")
		(net "GND")
	)
	(via
		(at 52.082446 -311.216802)
		(size 0.4572)
		(drill 0.2032)
		(layers "F.Cu" "B.Cu")
		(net "GND")
	)
	(via
		(at 65.597278 -33.980882)
		(size 0.508)
		(drill 0.254)
		(layers "F.Cu" "B.Cu")
		(net "GND")
	)
	(via
		(at 95.491554 -335.704434)
		(size 0.49022)
		(drill 0.254)
		(layers "F.Cu" "B.Cu")
		(net "GND")
	)
	(via
		(at 274.163282 -198.166736)
		(size 0.4572)
		(drill 0.2032)
		(layers "F.Cu" "B.Cu")
		(net "GND")
	)
	(via
		(at 35.976814 -305.266598)
		(size 0.4572)
		(drill 0.2032)
		(layers "F.Cu" "B.Cu")
		(net "GND")
	)
	(via
		(at 235.03128 -51.663346)
		(size 0.508)
		(drill 0.254)
		(layers "F.Cu" "B.Cu")
		(net "GND")
	)
	(via
		(at 92.954348 -286.475424)
		(size 0.4572)
		(drill 0.2032)
		(layers "F.Cu" "B.Cu")
		(net "GND")
	)
	(via
		(at 16.789146 -234.716574)
		(size 0.4572)
		(drill 0.2032)
		(layers "F.Cu" "B.Cu")
		(net "GND")
	)
	(via
		(at 393.046966 -10.16508)
		(size 0.508)
		(drill 0.254)
		(layers "F.Cu" "B.Cu")
		(net "GND")
	)
	(via
		(at 92.3925 -93.817948)
		(size 0.508)
		(drill 0.254)
		(layers "F.Cu" "B.Cu")
		(net "GND")
	)
	(via
		(at 414.16478 -159.095948)
		(size 0.508)
		(drill 0.254)
		(layers "F.Cu" "B.Cu")
		(net "GND")
	)
	(via
		(at 54.508146 -261.916672)
		(size 0.4572)
		(drill 0.2032)
		(layers "F.Cu" "B.Cu")
		(net "GND")
	)
	(via
		(at 86.375748 -273.453098)
		(size 0.4572)
		(drill 0.2032)
		(layers "F.Cu" "B.Cu")
		(net "GND")
	)
	(via
		(at 108.42625 -241.172746)
		(size 0.4572)
		(drill 0.2032)
		(layers "F.Cu" "B.Cu")
		(net "GND")
	)
	(via
		(at 367.406428 -331.776832)
		(size 0.49022)
		(drill 0.254)
		(layers "F.Cu" "B.Cu")
		(net "GND")
	)
	(via
		(at 2.764536 -198.550022)
		(size 0.508)
		(drill 0.254)
		(layers "F.Cu" "B.Cu")
		(net "GND")
	)
	(via
		(at 344.07348 -231.714548)
		(size 0.4572)
		(drill 0.2032)
		(layers "F.Cu" "B.Cu")
		(net "GND")
	)
	(via
		(at 377.54814 -335.187036)
		(size 0.49022)
		(drill 0.254)
		(layers "F.Cu" "B.Cu")
		(net "GND")
	)
	(via
		(at 274.163282 -261.066788)
		(size 0.4572)
		(drill 0.2032)
		(layers "F.Cu" "B.Cu")
		(net "GND")
	)
	(via
		(at 100.832666 -217.064336)
		(size 0.4572)
		(drill 0.2032)
		(layers "F.Cu" "B.Cu")
		(net "GND")
	)
	(via
		(at 181.49824 -345.64701)
		(size 0.508)
		(drill 0.254)
		(layers "F.Cu" "B.Cu")
		(net "GND")
	)
	(via
		(at 351.231962 -279.964134)
		(size 0.4572)
		(drill 0.2032)
		(layers "F.Cu" "B.Cu")
		(net "GND")
	)
	(via
		(at 137.484866 -246.364506)
		(size 0.4572)
		(drill 0.2032)
		(layers "F.Cu" "B.Cu")
		(net "GND")
	)
	(via
		(at 279.816814 -195.616576)
		(size 0.4572)
		(drill 0.2032)
		(layers "F.Cu" "B.Cu")
		(net "GND")
	)
	(via
		(at 54.835806 -4.962652)
		(size 0.508)
		(drill 0.254)
		(layers "F.Cu" "B.Cu")
		(net "GND")
	)
	(via
		(at 101.412548 -276.708616)
		(size 0.4572)
		(drill 0.2032)
		(layers "F.Cu" "B.Cu")
		(net "GND")
	)
	(via
		(at 266.619482 -261.066788)
		(size 0.4572)
		(drill 0.2032)
		(layers "F.Cu" "B.Cu")
		(net "GND")
	)
	(via
		(at 13.345414 -205.816708)
		(size 0.4572)
		(drill 0.2032)
		(layers "F.Cu" "B.Cu")
		(net "GND")
	)
	(via
		(at 334.315816 -273.453098)
		(size 0.4572)
		(drill 0.2032)
		(layers "F.Cu" "B.Cu")
		(net "GND")
	)
	(via
		(at 264.729214 -251.716794)
		(size 0.4572)
		(drill 0.2032)
		(layers "F.Cu" "B.Cu")
		(net "GND")
	)
	(via
		(at 197.637146 -309.51678)
		(size 0.4572)
		(drill 0.2032)
		(layers "F.Cu" "B.Cu")
		(net "GND")
	)
	(via
		(at 175.005746 -290.816792)
		(size 0.4572)
		(drill 0.2032)
		(layers "F.Cu" "B.Cu")
		(net "GND")
	)
	(via
		(at 37.940234 -106.523282)
		(size 0.508)
		(drill 0.254)
		(layers "F.Cu" "B.Cu")
		(net "GND")
	)
	(via
		(at 63.942214 -269.566644)
		(size 0.4572)
		(drill 0.2032)
		(layers "F.Cu" "B.Cu")
		(net "GND")
	)
	(via
		(at 207.071214 -289.966654)
		(size 0.4572)
		(drill 0.2032)
		(layers "F.Cu" "B.Cu")
		(net "GND")
	)
	(via
		(at 201.737214 -210.066636)
		(size 0.4572)
		(drill 0.2032)
		(layers "F.Cu" "B.Cu")
		(net "GND")
	)
	(via
		(at 104.911906 -334.282034)
		(size 0.49022)
		(drill 0.254)
		(layers "F.Cu" "B.Cu")
		(net "GND")
	)
	(via
		(at 368.618262 -264.50036)
		(size 0.4572)
		(drill 0.2032)
		(layers "F.Cu" "B.Cu")
		(net "GND")
	)
	(via
		(at 113.812066 -396.792958)
		(size 0.508)
		(drill 0.254)
		(layers "F.Cu" "B.Cu")
		(net "GND")
	)
	(via
		(at 9.277096 -101.095302)
		(size 0.508)
		(drill 0.254)
		(layers "F.Cu" "B.Cu")
		(net "GND")
	)
	(via
		(at 165.252146 -283.166566)
		(size 0.4572)
		(drill 0.2032)
		(layers "F.Cu" "B.Cu")
		(net "GND")
	)
	(via
		(at 464.764882 -303.566576)
		(size 0.4572)
		(drill 0.2032)
		(layers "F.Cu" "B.Cu")
		(net "GND")
	)
	(via
		(at 374.257316 -282.405836)
		(size 0.4572)
		(drill 0.2032)
		(layers "F.Cu" "B.Cu")
		(net "GND")
	)
	(via
		(at 412.393638 -407.638504)
		(size 0.4572)
		(drill 0.254)
		(layers "F.Cu" "B.Cu")
		(net "GND")
	)
	(via
		(at 373.67718 -245.55069)
		(size 0.4572)
		(drill 0.2032)
		(layers "F.Cu" "B.Cu")
		(net "GND")
	)
	(via
		(at 434.715158 -118.968266)
		(size 0.508)
		(drill 0.254)
		(layers "F.Cu" "B.Cu")
		(net "GND")
	)
	(via
		(at 195.427346 -212.616796)
		(size 0.4572)
		(drill 0.2032)
		(layers "F.Cu" "B.Cu")
		(net "GND")
	)
	(via
		(at 165.252146 -290.816792)
		(size 0.4572)
		(drill 0.2032)
		(layers "F.Cu" "B.Cu")
		(net "GND")
	)
	(via
		(at 352.531934 -226.831144)
		(size 0.4572)
		(drill 0.2032)
		(layers "F.Cu" "B.Cu")
		(net "GND")
	)
	(via
		(at 415.456878 -406.34666)
		(size 0.4572)
		(drill 0.254)
		(layers "F.Cu" "B.Cu")
		(net "GND")
	)
	(via
		(at 370.51488 -37.937948)
		(size 0.508)
		(drill 0.254)
		(layers "F.Cu" "B.Cu")
		(net "GND")
	)
	(via
		(at 447.467482 -250.866656)
		(size 0.4572)
		(drill 0.2032)
		(layers "F.Cu" "B.Cu")
		(net "GND")
	)
	(via
		(at 26.223214 -280.61666)
		(size 0.4572)
		(drill 0.2032)
		(layers "F.Cu" "B.Cu")
		(net "GND")
	)
	(via
		(at 432.379882 -266.1666)
		(size 0.4572)
		(drill 0.2032)
		(layers "F.Cu" "B.Cu")
		(net "GND")
	)
	(via
		(at 364.389416 -288.103056)
		(size 0.4572)
		(drill 0.2032)
		(layers "F.Cu" "B.Cu")
		(net "GND")
	)
	(via
		(at 93.456506 -331.043026)
		(size 0.508)
		(drill 0.254)
		(layers "F.Cu" "B.Cu")
		(net "GND")
	)
	(via
		(at 327.927208 -403.883876)
		(size 0.4064)
		(drill 0.2032)
		(layers "F.Cu" "B.Cu")
		(net "GND")
	)
	(via
		(at 159.918146 -203.266802)
		(size 0.4572)
		(drill 0.2032)
		(layers "F.Cu" "B.Cu")
		(net "GND")
	)
	(via
		(at 268.829282 -261.066788)
		(size 0.4572)
		(drill 0.2032)
		(layers "F.Cu" "B.Cu")
		(net "GND")
	)
	(via
		(at 419.573964 -441.225432)
		(size 0.508)
		(drill 0.254)
		(layers "F.Cu" "B.Cu")
		(net "GND")
	)
	(via
		(at 210.514946 -212.616796)
		(size 0.4572)
		(drill 0.2032)
		(layers "F.Cu" "B.Cu")
		(net "GND")
	)
	(via
		(at 197.637146 -220.266768)
		(size 0.4572)
		(drill 0.2032)
		(layers "F.Cu" "B.Cu")
		(net "GND")
	)
	(via
		(at 52.298346 -298.466764)
		(size 0.4572)
		(drill 0.2032)
		(layers "F.Cu" "B.Cu")
		(net "GND")
	)
	(via
		(at 335.725262 -266.128246)
		(size 0.4572)
		(drill 0.2032)
		(layers "F.Cu" "B.Cu")
		(net "GND")
	)
	(via
		(at 96.133412 -236.597952)
		(size 0.4572)
		(drill 0.2032)
		(layers "F.Cu" "B.Cu")
		(net "GND")
	)
	(via
		(at 79.17053 -344.90533)
		(size 0.49022)
		(drill 0.254)
		(layers "F.Cu" "B.Cu")
		(net "GND")
	)
	(via
		(at 287.360614 -285.716726)
		(size 0.4572)
		(drill 0.2032)
		(layers "F.Cu" "B.Cu")
		(net "GND")
	)
	(via
		(at 212.724746 -210.916774)
		(size 0.4572)
		(drill 0.2032)
		(layers "F.Cu" "B.Cu")
		(net "GND")
	)
	(via
		(at 165.252146 -234.716574)
		(size 0.4572)
		(drill 0.2032)
		(layers "F.Cu" "B.Cu")
		(net "GND")
	)
	(via
		(at 415.689796 -206.666592)
		(size 0.4572)
		(drill 0.2032)
		(layers "F.Cu" "B.Cu")
		(net "GND")
	)
	(via
		(at 115.423442 -241.665506)
		(size 0.4572)
		(drill 0.2032)
		(layers "F.Cu" "B.Cu")
		(net "GND")
	)
	(via
		(at 194.193414 -308.666642)
		(size 0.4572)
		(drill 0.2032)
		(layers "F.Cu" "B.Cu")
		(net "GND")
	)
	(via
		(at 380.256034 -219.506038)
		(size 0.4572)
		(drill 0.2032)
		(layers "F.Cu" "B.Cu")
		(net "GND")
	)
	(via
		(at 462.555082 -235.566712)
		(size 0.4572)
		(drill 0.2032)
		(layers "F.Cu" "B.Cu")
		(net "GND")
	)
	(via
		(at 195.427346 -233.016806)
		(size 0.4572)
		(drill 0.2032)
		(layers "F.Cu" "B.Cu")
		(net "GND")
	)
	(via
		(at 7.035546 -270.416782)
		(size 0.4572)
		(drill 0.2032)
		(layers "F.Cu" "B.Cu")
		(net "GND")
	)
	(via
		(at 435.606952 -386.321554)
		(size 0.508)
		(drill 0.254)
		(layers "F.Cu" "B.Cu")
		(net "GND")
	)
	(via
		(at 18.679414 -219.41663)
		(size 0.4572)
		(drill 0.2032)
		(layers "F.Cu" "B.Cu")
		(net "GND")
	)
	(via
		(at 28.433014 -219.41663)
		(size 0.4572)
		(drill 0.2032)
		(layers "F.Cu" "B.Cu")
		(net "GND")
	)
	(via
		(at 281.707082 -233.86669)
		(size 0.4572)
		(drill 0.2032)
		(layers "F.Cu" "B.Cu")
		(net "GND")
	)
	(via
		(at 11.135614 -196.466714)
		(size 0.4572)
		(drill 0.2032)
		(layers "F.Cu" "B.Cu")
		(net "GND")
	)
	(via
		(at 199.527414 -235.566712)
		(size 0.4572)
		(drill 0.2032)
		(layers "F.Cu" "B.Cu")
		(net "GND")
	)
	(via
		(at 58.608214 -241.516662)
		(size 0.4572)
		(drill 0.2032)
		(layers "F.Cu" "B.Cu")
		(net "GND")
	)
	(via
		(at 157.708346 -244.916706)
		(size 0.4572)
		(drill 0.2032)
		(layers "F.Cu" "B.Cu")
		(net "GND")
	)
	(via
		(at 28.433014 -267.866622)
		(size 0.4572)
		(drill 0.2032)
		(layers "F.Cu" "B.Cu")
		(net "GND")
	)
	(via
		(at 33.767014 -272.966688)
		(size 0.4572)
		(drill 0.2032)
		(layers "F.Cu" "B.Cu")
		(net "GND")
	)
	(via
		(at 378.846334 -247.992138)
		(size 0.4572)
		(drill 0.2032)
		(layers "F.Cu" "B.Cu")
		(net "GND")
	)
	(via
		(at 407.858214 -242.3668)
		(size 0.4572)
		(drill 0.2032)
		(layers "F.Cu" "B.Cu")
		(net "GND")
	)
	(via
		(at 405.648414 -225.36658)
		(size 0.4572)
		(drill 0.2032)
		(layers "F.Cu" "B.Cu")
		(net "GND")
	)
	(via
		(at 49.751996 -354.109528)
		(size 0.49022)
		(drill 0.254)
		(layers "F.Cu" "B.Cu")
		(net "GND")
	)
	(via
		(at 335.725262 -264.50036)
		(size 0.4572)
		(drill 0.2032)
		(layers "F.Cu" "B.Cu")
		(net "GND")
	)
	(via
		(at 33.58515 -128.109472)
		(size 0.508)
		(drill 0.254)
		(layers "F.Cu" "B.Cu")
		(net "GND")
	)
	(via
		(at 165.252146 -250.016772)
		(size 0.4572)
		(drill 0.2032)
		(layers "F.Cu" "B.Cu")
		(net "GND")
	)
	(via
		(at 434.589682 -250.866656)
		(size 0.4572)
		(drill 0.2032)
		(layers "F.Cu" "B.Cu")
		(net "GND")
	)
	(via
		(at 136.184894 -253.919736)
		(size 0.4572)
		(drill 0.2032)
		(layers "F.Cu" "B.Cu")
		(net "GND")
	)
	(via
		(at 33.767014 -198.166736)
		(size 0.4572)
		(drill 0.2032)
		(layers "F.Cu" "B.Cu")
		(net "GND")
	)
	(via
		(at 350.762062 -266.128246)
		(size 0.4572)
		(drill 0.2032)
		(layers "F.Cu" "B.Cu")
		(net "GND")
	)
	(via
		(at 122.616214 -365.429292)
		(size 0.508)
		(drill 0.254)
		(layers "F.Cu" "B.Cu")
		(net "GND")
	)
	(via
		(at 18.679414 -221.116652)
		(size 0.4572)
		(drill 0.2032)
		(layers "F.Cu" "B.Cu")
		(net "GND")
	)
	(via
		(at 462.555082 -295.916604)
		(size 0.4572)
		(drill 0.2032)
		(layers "F.Cu" "B.Cu")
		(net "GND")
	)
	(via
		(at 266.4714 -99.101148)
		(size 0.508)
		(drill 0.254)
		(layers "F.Cu" "B.Cu")
		(net "GND")
	)
	(via
		(at 118.433088 -257.69316)
		(size 0.4572)
		(drill 0.2032)
		(layers "F.Cu" "B.Cu")
		(net "GND")
	)
	(via
		(at 221.31528 -105.855008)
		(size 0.508)
		(drill 0.254)
		(layers "F.Cu" "B.Cu")
		(net "GND")
	)
	(via
		(at 56.72582 -108.322618)
		(size 0.508)
		(drill 0.254)
		(layers "F.Cu" "B.Cu")
		(net "GND")
	)
	(via
		(at 91.434666 -243.108988)
		(size 0.4572)
		(drill 0.2032)
		(layers "F.Cu" "B.Cu")
		(net "GND")
	)
	(via
		(at 381.775462 -282.405836)
		(size 0.4572)
		(drill 0.2032)
		(layers "F.Cu" "B.Cu")
		(net "GND")
	)
	(via
		(at 421.23106 -360.074972)
		(size 0.508)
		(drill 0.254)
		(layers "F.Cu" "B.Cu")
		(net "GND")
	)
	(via
		(at 443.367414 -242.3668)
		(size 0.4572)
		(drill 0.2032)
		(layers "F.Cu" "B.Cu")
		(net "GND")
	)
	(via
		(at 327.250044 -430.299622)
		(size 0.4572)
		(drill 0.2032)
		(layers "F.Cu" "B.Cu")
		(net "GND")
	)
	(via
		(at 63.098426 -401.492212)
		(size 0.4572)
		(drill 0.254)
		(layers "F.Cu" "B.Cu")
		(net "GND")
	)
	(via
		(at 450.911214 -206.666592)
		(size 0.4572)
		(drill 0.2032)
		(layers "F.Cu" "B.Cu")
		(net "GND")
	)
	(via
		(at 161.628328 -216.90457)
		(size 0.4572)
		(drill 0.2032)
		(layers "F.Cu" "B.Cu")
		(net "GND")
	)
	(via
		(at 427.582076 -119.349012)
		(size 0.508)
		(drill 0.254)
		(layers "F.Cu" "B.Cu")
		(net "GND")
	)
	(via
		(at 163.933378 -421.74795)
		(size 0.508)
		(drill 0.254)
		(layers "F.Cu" "B.Cu")
		(net "GND")
	)
	(via
		(at 208.517744 -90.666824)
		(size 0.508)
		(drill 0.254)
		(layers "F.Cu" "B.Cu")
		(net "GND")
	)
	(via
		(at 438.033414 -199.01662)
		(size 0.4572)
		(drill 0.2032)
		(layers "F.Cu" "B.Cu")
		(net "GND")
	)
	(via
		(at 326.246998 -58.49112)
		(size 0.508)
		(drill 0.254)
		(layers "F.Cu" "B.Cu")
		(net "GND")
	)
	(via
		(at 51.064414 -230.466646)
		(size 0.4572)
		(drill 0.2032)
		(layers "F.Cu" "B.Cu")
		(net "GND")
	)
	(via
		(at 455.011282 -275.516594)
		(size 0.4572)
		(drill 0.2032)
		(layers "F.Cu" "B.Cu")
		(net "GND")
	)
	(via
		(at 315.57722 -409.396184)
		(size 0.4572)
		(drill 0.254)
		(layers "F.Cu" "B.Cu")
		(net "GND")
	)
	(via
		(at 382.715262 -284.033722)
		(size 0.4572)
		(drill 0.2032)
		(layers "F.Cu" "B.Cu")
		(net "GND")
	)
	(via
		(at 105.641394 -277.522432)
		(size 0.4572)
		(drill 0.2032)
		(layers "F.Cu" "B.Cu")
		(net "GND")
	)
	(via
		(at 14.579346 -306.116736)
		(size 0.4572)
		(drill 0.2032)
		(layers "F.Cu" "B.Cu")
		(net "GND")
	)
	(via
		(at 27.9908 -407.7208)
		(size 0.508)
		(drill 0.254)
		(layers "F.Cu" "B.Cu")
		(net "GND")
	)
	(via
		(at 434.589682 -272.966688)
		(size 0.4572)
		(drill 0.2032)
		(layers "F.Cu" "B.Cu")
		(net "GND")
	)
	(via
		(at 81.380838 -407.00452)
		(size 0.4064)
		(drill 0.2032)
		(layers "F.Cu" "B.Cu")
		(net "GND")
	)
	(via
		(at 159.561276 -43.274488)
		(size 0.508)
		(drill 0.254)
		(layers "F.Cu" "B.Cu")
		(net "GND")
	)
	(via
		(at 131.015994 -254.733552)
		(size 0.4572)
		(drill 0.2032)
		(layers "F.Cu" "B.Cu")
		(net "GND")
	)
	(via
		(at 58.844942 -18.502376)
		(size 0.508)
		(drill 0.254)
		(layers "F.Cu" "B.Cu")
		(net "GND")
	)
	(via
		(at 43.520614 -198.166736)
		(size 0.4572)
		(drill 0.2032)
		(layers "F.Cu" "B.Cu")
		(net "GND")
	)
	(via
		(at 344.86342 -403.249892)
		(size 0.4572)
		(drill 0.254)
		(layers "F.Cu" "B.Cu")
		(net "GND")
	)
	(via
		(at 289.250882 -269.566644)
		(size 0.4572)
		(drill 0.2032)
		(layers "F.Cu" "B.Cu")
		(net "GND")
	)
	(via
		(at 266.619482 -272.966688)
		(size 0.4572)
		(drill 0.2032)
		(layers "F.Cu" "B.Cu")
		(net "GND")
	)
	(via
		(at 383.185416 -275.080984)
		(size 0.4572)
		(drill 0.2032)
		(layers "F.Cu" "B.Cu")
		(net "GND")
	)
	(via
		(at 411.958282 -196.466714)
		(size 0.4572)
		(drill 0.2032)
		(layers "F.Cu" "B.Cu")
		(net "GND")
	)
	(via
		(at 49.431194 -6.597396)
		(size 0.508)
		(drill 0.254)
		(layers "F.Cu" "B.Cu")
		(net "GND")
	)
	(via
		(at 249.86488 -130.139948)
		(size 0.508)
		(drill 0.254)
		(layers "F.Cu" "B.Cu")
		(net "GND")
	)
	(via
		(at 165.252146 -248.31675)
		(size 0.4572)
		(drill 0.2032)
		(layers "F.Cu" "B.Cu")
		(net "GND")
	)
	(via
		(at 337.965034 -219.506038)
		(size 0.4572)
		(drill 0.2032)
		(layers "F.Cu" "B.Cu")
		(net "GND")
	)
	(via
		(at 382.60528 -244.73662)
		(size 0.4572)
		(drill 0.2032)
		(layers "F.Cu" "B.Cu")
		(net "GND")
	)
	(via
		(at 52.10429 -404.51786)
		(size 0.4572)
		(drill 0.254)
		(layers "F.Cu" "B.Cu")
		(net "GND")
	)
	(via
		(at 195.427346 -221.96679)
		(size 0.4572)
		(drill 0.2032)
		(layers "F.Cu" "B.Cu")
		(net "GND")
	)
	(via
		(at 29.77388 -426.792898)
		(size 0.508)
		(drill 0.254)
		(layers "F.Cu" "B.Cu")
		(net "GND")
	)
	(via
		(at 355.96576 -331.08392)
		(size 0.508)
		(drill 0.254)
		(layers "F.Cu" "B.Cu")
		(net "GND")
	)
	(via
		(at 6.76021 -170.189144)
		(size 0.508)
		(drill 0.254)
		(layers "F.Cu" "B.Cu")
		(net "GND")
	)
	(via
		(at 418.36594 -110.280958)
		(size 0.508)
		(drill 0.254)
		(layers "F.Cu" "B.Cu")
		(net "GND")
	)
	(via
		(at 45.900594 -4.962652)
		(size 0.508)
		(drill 0.254)
		(layers "F.Cu" "B.Cu")
		(net "GND")
	)
	(via
		(at 439.923682 -267.866622)
		(size 0.4572)
		(drill 0.2032)
		(layers "F.Cu" "B.Cu")
		(net "GND")
	)
	(via
		(at 51.064414 -245.76659)
		(size 0.4572)
		(drill 0.2032)
		(layers "F.Cu" "B.Cu")
		(net "GND")
	)
	(via
		(at 419.502082 -222.816674)
		(size 0.4572)
		(drill 0.2032)
		(layers "F.Cu" "B.Cu")
		(net "GND")
	)
	(via
		(at 409.330398 -406.370536)
		(size 0.4572)
		(drill 0.254)
		(layers "F.Cu" "B.Cu")
		(net "GND")
	)
	(via
		(at 337.299808 -46.449996)
		(size 0.4572)
		(drill 0.2032)
		(layers "F.Cu" "B.Cu")
		(net "GND")
	)
	(via
		(at 131.376166 -219.506038)
		(size 0.4572)
		(drill 0.2032)
		(layers "F.Cu" "B.Cu")
		(net "GND")
	)
	(via
		(at 76.186538 -20.135342)
		(size 0.508)
		(drill 0.254)
		(layers "F.Cu" "B.Cu")
		(net "GND")
	)
	(via
		(at 361.929934 -220.319854)
		(size 0.4572)
		(drill 0.2032)
		(layers "F.Cu" "B.Cu")
		(net "GND")
	)
	(via
		(at 89.554812 -241.481102)
		(size 0.4572)
		(drill 0.2032)
		(layers "F.Cu" "B.Cu")
		(net "GND")
	)
	(via
		(at 407.858214 -296.766742)
		(size 0.4572)
		(drill 0.2032)
		(layers "F.Cu" "B.Cu")
		(net "GND")
	)
	(via
		(at 363.656118 -362.618528)
		(size 0.508)
		(drill 0.254)
		(layers "F.Cu" "B.Cu")
		(net "GND")
	)
	(via
		(at 88.145366 -224.389442)
		(size 0.4572)
		(drill 0.2032)
		(layers "F.Cu" "B.Cu")
		(net "GND")
	)
	(via
		(at 285.150814 -306.116736)
		(size 0.4572)
		(drill 0.2032)
		(layers "F.Cu" "B.Cu")
		(net "GND")
	)
	(via
		(at 28.638246 -390.294876)
		(size 0.508)
		(drill 0.254)
		(layers "F.Cu" "B.Cu")
		(net "GND")
	)
	(via
		(at 209.281014 -301.01667)
		(size 0.4572)
		(drill 0.2032)
		(layers "F.Cu" "B.Cu")
		(net "GND")
	)
	(via
		(at 358.170734 -234.970066)
		(size 0.4572)
		(drill 0.2032)
		(layers "F.Cu" "B.Cu")
		(net "GND")
	)
	(via
		(at 430.489614 -203.266802)
		(size 0.4572)
		(drill 0.2032)
		(layers "F.Cu" "B.Cu")
		(net "GND")
	)
	(via
		(at 159.918146 -229.616762)
		(size 0.4572)
		(drill 0.2032)
		(layers "F.Cu" "B.Cu")
		(net "GND")
	)
	(via
		(at 356.871016 -265.314176)
		(size 0.4572)
		(drill 0.2032)
		(layers "F.Cu" "B.Cu")
		(net "GND")
	)
	(via
		(at 205.180946 -220.266768)
		(size 0.4572)
		(drill 0.2032)
		(layers "F.Cu" "B.Cu")
		(net "GND")
	)
	(via
		(at 91.904312 -247.178322)
		(size 0.4572)
		(drill 0.2032)
		(layers "F.Cu" "B.Cu")
		(net "GND")
	)
	(via
		(at 154.999182 -410.664152)
		(size 0.4572)
		(drill 0.254)
		(layers "F.Cu" "B.Cu")
		(net "GND")
	)
	(via
		(at 304.338482 -261.066788)
		(size 0.4572)
		(drill 0.2032)
		(layers "F.Cu" "B.Cu")
		(net "GND")
	)
	(via
		(at 20.889214 -241.516662)
		(size 0.4572)
		(drill 0.2032)
		(layers "F.Cu" "B.Cu")
		(net "GND")
	)
	(via
		(at 458.455014 -311.216802)
		(size 0.4572)
		(drill 0.2032)
		(layers "F.Cu" "B.Cu")
		(net "GND")
	)
	(via
		(at 261.285482 -205.816708)
		(size 0.4572)
		(drill 0.2032)
		(layers "F.Cu" "B.Cu")
		(net "GND")
	)
	(via
		(at 311.255156 -410.664152)
		(size 0.4572)
		(drill 0.254)
		(layers "F.Cu" "B.Cu")
		(net "GND")
	)
	(via
		(at 428.279814 -214.316564)
		(size 0.4572)
		(drill 0.2032)
		(layers "F.Cu" "B.Cu")
		(net "GND")
	)
	(via
		(at 147.165314 -400.858228)
		(size 0.4064)
		(drill 0.2032)
		(layers "F.Cu" "B.Cu")
		(net "GND")
	)
	(via
		(at 339.014562 -271.825212)
		(size 0.4572)
		(drill 0.2032)
		(layers "F.Cu" "B.Cu")
		(net "GND")
	)
	(via
		(at 110.305088 -295.03878)
		(size 0.508)
		(drill 0.254)
		(layers "F.Cu" "B.Cu")
		(net "GND")
	)
	(via
		(at 111.640366 -227.64496)
		(size 0.4572)
		(drill 0.2032)
		(layers "F.Cu" "B.Cu")
		(net "GND")
	)
	(via
		(at 16.59509 -18.246344)
		(size 0.508)
		(drill 0.254)
		(layers "F.Cu" "B.Cu")
		(net "GND")
	)
	(via
		(at 331.254608 -410.030168)
		(size 0.4064)
		(drill 0.2032)
		(layers "F.Cu" "B.Cu")
		(net "GND")
	)
	(via
		(at 369.918234 -234.15625)
		(size 0.4572)
		(drill 0.2032)
		(layers "F.Cu" "B.Cu")
		(net "GND")
	)
	(via
		(at 52.298346 -263.616694)
		(size 0.4572)
		(drill 0.2032)
		(layers "F.Cu" "B.Cu")
		(net "GND")
	)
	(via
		(at 133.928612 -41.840404)
		(size 0.508)
		(drill 0.254)
		(layers "F.Cu" "B.Cu")
		(net "GND")
	)
	(via
		(at 90.306398 -403.883876)
		(size 0.4064)
		(drill 0.2032)
		(layers "F.Cu" "B.Cu")
		(net "GND")
	)
	(via
		(at 300.238414 -201.56678)
		(size 0.4572)
		(drill 0.2032)
		(layers "F.Cu" "B.Cu")
		(net "GND")
	)
	(via
		(at 135.135366 -242.294918)
		(size 0.4572)
		(drill 0.2032)
		(layers "F.Cu" "B.Cu")
		(net "GND")
	)
	(via
		(at 283.916882 -312.91657)
		(size 0.4572)
		(drill 0.2032)
		(layers "F.Cu" "B.Cu")
		(net "GND")
	)
	(via
		(at 412.66745 -403.883876)
		(size 0.4064)
		(drill 0.2032)
		(layers "F.Cu" "B.Cu")
		(net "GND")
	)
	(via
		(at 327.66127 -74.617072)
		(size 0.508)
		(drill 0.254)
		(layers "F.Cu" "B.Cu")
		(net "GND")
	)
	(via
		(at 268.829282 -207.51673)
		(size 0.4572)
		(drill 0.2032)
		(layers "F.Cu" "B.Cu")
		(net "GND")
	)
	(via
		(at 425.705016 -137.93851)
		(size 0.508)
		(drill 0.254)
		(layers "F.Cu" "B.Cu")
		(net "GND")
	)
	(via
		(at 25.83688 -101.818948)
		(size 0.508)
		(drill 0.254)
		(layers "F.Cu" "B.Cu")
		(net "GND")
	)
	(via
		(at 172.795946 -304.416714)
		(size 0.4572)
		(drill 0.2032)
		(layers "F.Cu" "B.Cu")
		(net "GND")
	)
	(via
		(at 414.85947 -162.877754)
		(size 0.49022)
		(drill 0.254)
		(layers "F.Cu" "B.Cu")
		(net "GND")
	)
	(via
		(at 144.005046 -406.370536)
		(size 0.4572)
		(drill 0.254)
		(layers "F.Cu" "B.Cu")
		(net "GND")
	)
	(via
		(at 462.555082 -198.166736)
		(size 0.4572)
		(drill 0.2032)
		(layers "F.Cu" "B.Cu")
		(net "GND")
	)
	(via
		(at 412.355792 -358.705912)
		(size 0.508)
		(drill 0.254)
		(layers "F.Cu" "B.Cu")
		(net "GND")
	)
	(via
		(at 113.629694 -284.847538)
		(size 0.4572)
		(drill 0.2032)
		(layers "F.Cu" "B.Cu")
		(net "GND")
	)
	(via
		(at 339.374734 -228.45903)
		(size 0.4572)
		(drill 0.2032)
		(layers "F.Cu" "B.Cu")
		(net "GND")
	)
	(via
		(at 156.355034 -403.883876)
		(size 0.4064)
		(drill 0.2032)
		(layers "F.Cu" "B.Cu")
		(net "GND")
	)
	(via
		(at 417.292282 -250.866656)
		(size 0.4572)
		(drill 0.2032)
		(layers "F.Cu" "B.Cu")
		(net "GND")
	)
	(via
		(at 69.66458 -189.636908)
		(size 0.508)
		(drill 0.254)
		(layers "F.Cu" "B.Cu")
		(net "GND")
	)
	(via
		(at 424.836082 -284.866588)
		(size 0.4572)
		(drill 0.2032)
		(layers "F.Cu" "B.Cu")
		(net "GND")
	)
	(via
		(at 276.373082 -295.916604)
		(size 0.4572)
		(drill 0.2032)
		(layers "F.Cu" "B.Cu")
		(net "GND")
	)
	(via
		(at 345.593416 -253.919736)
		(size 0.4572)
		(drill 0.2032)
		(layers "F.Cu" "B.Cu")
		(net "GND")
	)
	(via
		(at 84.386166 -247.178322)
		(size 0.4572)
		(drill 0.2032)
		(layers "F.Cu" "B.Cu")
		(net "GND")
	)
	(via
		(at 41.310814 -280.61666)
		(size 0.4572)
		(drill 0.2032)
		(layers "F.Cu" "B.Cu")
		(net "GND")
	)
	(via
		(at 66.367914 -310.366664)
		(size 0.4572)
		(drill 0.2032)
		(layers "F.Cu" "B.Cu")
		(net "GND")
	)
	(via
		(at 361.460034 -219.506038)
		(size 0.4572)
		(drill 0.2032)
		(layers "F.Cu" "B.Cu")
		(net "GND")
	)
	(via
		(at 281.707082 -226.216718)
		(size 0.4572)
		(drill 0.2032)
		(layers "F.Cu" "B.Cu")
		(net "GND")
	)
	(via
		(at 205.180946 -234.716574)
		(size 0.4572)
		(drill 0.2032)
		(layers "F.Cu" "B.Cu")
		(net "GND")
	)
	(via
		(at 261.285482 -194.766692)
		(size 0.4572)
		(drill 0.2032)
		(layers "F.Cu" "B.Cu")
		(net "GND")
	)
	(via
		(at 376.21337 -354.670868)
		(size 0.508)
		(drill 0.254)
		(layers "F.Cu" "B.Cu")
		(net "GND")
	)
	(via
		(at 109.760766 -229.272846)
		(size 0.4572)
		(drill 0.2032)
		(layers "F.Cu" "B.Cu")
		(net "GND")
	)
	(via
		(at 145.349976 -433.747164)
		(size 0.4572)
		(drill 0.2032)
		(layers "F.Cu" "B.Cu")
		(net "GND")
	)
	(via
		(at 336.766408 -54.558946)
		(size 0.4572)
		(drill 0.2032)
		(layers "F.Cu" "B.Cu")
		(net "GND")
	)
	(via
		(at 403.293072 -0.76454)
		(size 0.508)
		(drill 0.254)
		(layers "F.Cu" "B.Cu")
		(net "GND")
	)
	(via
		(at 305.58994 -429.632618)
		(size 0.508)
		(drill 0.254)
		(layers "F.Cu" "B.Cu")
		(net "GND")
	)
	(via
		(at 407.858214 -281.466798)
		(size 0.4572)
		(drill 0.2032)
		(layers "F.Cu" "B.Cu")
		(net "GND")
	)
	(via
		(at 419.502082 -289.966654)
		(size 0.4572)
		(drill 0.2032)
		(layers "F.Cu" "B.Cu")
		(net "GND")
	)
	(via
		(at 121.303542 -406.370536)
		(size 0.4572)
		(drill 0.254)
		(layers "F.Cu" "B.Cu")
		(net "GND")
	)
	(via
		(at 118.615968 -37.055552)
		(size 0.508)
		(drill 0.254)
		(layers "F.Cu" "B.Cu")
		(net "GND")
	)
	(via
		(at 179.105814 -280.61666)
		(size 0.4572)
		(drill 0.2032)
		(layers "F.Cu" "B.Cu")
		(net "GND")
	)
	(via
		(at 63.942214 -213.46668)
		(size 0.4572)
		(drill 0.2032)
		(layers "F.Cu" "B.Cu")
		(net "GND")
	)
	(via
		(at 454.987406 -78.402434)
		(size 0.508)
		(drill 0.254)
		(layers "F.Cu" "B.Cu")
		(net "GND")
	)
	(via
		(at 283.916882 -241.516662)
		(size 0.4572)
		(drill 0.2032)
		(layers "F.Cu" "B.Cu")
		(net "GND")
	)
	(via
		(at 115.03533 -441.225432)
		(size 0.508)
		(drill 0.254)
		(layers "F.Cu" "B.Cu")
		(net "GND")
	)
	(via
		(at 329.908408 -403.883876)
		(size 0.4064)
		(drill 0.2032)
		(layers "F.Cu" "B.Cu")
		(net "GND")
	)
	(via
		(at 374.257062 -284.033722)
		(size 0.4572)
		(drill 0.2032)
		(layers "F.Cu" "B.Cu")
		(net "GND")
	)
	(via
		(at 20.889214 -306.96662)
		(size 0.4572)
		(drill 0.2032)
		(layers "F.Cu" "B.Cu")
		(net "GND")
	)
	(via
		(at 262.519414 -251.716794)
		(size 0.4572)
		(drill 0.2032)
		(layers "F.Cu" "B.Cu")
		(net "GND")
	)
	(via
		(at 69.224906 -400.224244)
		(size 0.4572)
		(drill 0.254)
		(layers "F.Cu" "B.Cu")
		(net "GND")
	)
	(via
		(at 439.923682 -232.166668)
		(size 0.4572)
		(drill 0.2032)
		(layers "F.Cu" "B.Cu")
		(net "GND")
	)
	(via
		(at 307.782214 -234.716574)
		(size 0.4572)
		(drill 0.2032)
		(layers "F.Cu" "B.Cu")
		(net "GND")
	)
	(via
		(at 159.977582 -295.041574)
		(size 0.4572)
		(drill 0.2032)
		(layers "F.Cu" "B.Cu")
		(net "GND")
	)
	(via
		(at 450.911214 -285.716726)
		(size 0.4572)
		(drill 0.2032)
		(layers "F.Cu" "B.Cu")
		(net "GND")
	)
	(via
		(at 349.556832 -329.078844)
		(size 0.508)
		(drill 0.254)
		(layers "F.Cu" "B.Cu")
		(net "GND")
	)
	(via
		(at 450.911214 -296.766742)
		(size 0.4572)
		(drill 0.2032)
		(layers "F.Cu" "B.Cu")
		(net "GND")
	)
	(via
		(at 335.725262 -257.98907)
		(size 0.4318)
		(drill 0.2032)
		(layers "F.Cu" "B.Cu")
		(net "GND")
	)
	(via
		(at 20.785582 -429.047148)
		(size 0.508)
		(drill 0.254)
		(layers "F.Cu" "B.Cu")
		(net "GND")
	)
	(via
		(at 167.81526 -103.673148)
		(size 0.508)
		(drill 0.254)
		(layers "F.Cu" "B.Cu")
		(net "GND")
	)
	(via
		(at 179.105814 -233.86669)
		(size 0.4572)
		(drill 0.2032)
		(layers "F.Cu" "B.Cu")
		(net "GND")
	)
	(via
		(at 95.56623 -57.241948)
		(size 0.508)
		(drill 0.254)
		(layers "F.Cu" "B.Cu")
		(net "GND")
	)
	(via
		(at 361.460034 -232.528364)
		(size 0.4572)
		(drill 0.2032)
		(layers "F.Cu" "B.Cu")
		(net "GND")
	)
	(via
		(at 22.123146 -234.716574)
		(size 0.4572)
		(drill 0.2032)
		(layers "F.Cu" "B.Cu")
		(net "GND")
	)
	(via
		(at 300.238414 -244.916706)
		(size 0.4572)
		(drill 0.2032)
		(layers "F.Cu" "B.Cu")
		(net "GND")
	)
	(via
		(at 88.250014 -438.651396)
		(size 0.4572)
		(drill 0.2032)
		(layers "F.Cu" "B.Cu")
		(net "GND")
	)
	(via
		(at 371.764306 -172.100748)
		(size 0.508)
		(drill 0.254)
		(layers "F.Cu" "B.Cu")
		(net "GND")
	)
	(via
		(at 345.15171 -49.59096)
		(size 0.4572)
		(drill 0.2032)
		(layers "F.Cu" "B.Cu")
		(net "GND")
	)
	(via
		(at 129.966212 -249.620024)
		(size 0.4572)
		(drill 0.2032)
		(layers "F.Cu" "B.Cu")
		(net "GND")
	)
	(via
		(at 335.615534 -247.992138)
		(size 0.4572)
		(drill 0.2032)
		(layers "F.Cu" "B.Cu")
		(net "GND")
	)
	(via
		(at 346.532962 -265.314176)
		(size 0.4572)
		(drill 0.2032)
		(layers "F.Cu" "B.Cu")
		(net "GND")
	)
	(via
		(at 434.589682 -247.466612)
		(size 0.4572)
		(drill 0.2032)
		(layers "F.Cu" "B.Cu")
		(net "GND")
	)
	(via
		(at 18.679414 -238.116618)
		(size 0.4572)
		(drill 0.2032)
		(layers "F.Cu" "B.Cu")
		(net "GND")
	)
	(via
		(at 412.220664 -207.51673)
		(size 0.4572)
		(drill 0.2032)
		(layers "F.Cu" "B.Cu")
		(net "GND")
	)
	(via
		(at 134.305548 -281.59202)
		(size 0.4572)
		(drill 0.2032)
		(layers "F.Cu" "B.Cu")
		(net "GND")
	)
	(via
		(at 292.694614 -236.416596)
		(size 0.4572)
		(drill 0.2032)
		(layers "F.Cu" "B.Cu")
		(net "GND")
	)
	(via
		(at 205.180946 -206.666592)
		(size 0.4572)
		(drill 0.2032)
		(layers "F.Cu" "B.Cu")
		(net "GND")
	)
	(via
		(at 108.820966 -219.506038)
		(size 0.4572)
		(drill 0.2032)
		(layers "F.Cu" "B.Cu")
		(net "GND")
	)
	(via
		(at 167.461946 -238.966756)
		(size 0.4572)
		(drill 0.2032)
		(layers "F.Cu" "B.Cu")
		(net "GND")
	)
	(via
		(at 268.205712 -66.323972)
		(size 0.508)
		(drill 0.254)
		(layers "F.Cu" "B.Cu")
		(net "GND")
	)
	(via
		(at 299.004482 -271.266666)
		(size 0.4572)
		(drill 0.2032)
		(layers "F.Cu" "B.Cu")
		(net "GND")
	)
	(via
		(at 70.571106 -407.638504)
		(size 0.4572)
		(drill 0.254)
		(layers "F.Cu" "B.Cu")
		(net "GND")
	)
	(via
		(at 129.136394 -259.616956)
		(size 0.4572)
		(drill 0.2032)
		(layers "F.Cu" "B.Cu")
		(net "GND")
	)
	(via
		(at 409.748482 -297.616626)
		(size 0.4572)
		(drill 0.2032)
		(layers "F.Cu" "B.Cu")
		(net "GND")
	)
	(via
		(at 61.212222 -160.22828)
		(size 0.508)
		(drill 0.254)
		(layers "F.Cu" "B.Cu")
		(net "GND")
	)
	(via
		(at 136.619742 -407.638504)
		(size 0.4572)
		(drill 0.254)
		(layers "F.Cu" "B.Cu")
		(net "GND")
	)
	(via
		(at 262.519414 -304.416714)
		(size 0.4572)
		(drill 0.2032)
		(layers "F.Cu" "B.Cu")
		(net "GND")
	)
	(via
		(at 54.284118 -17.61236)
		(size 0.508)
		(drill 0.254)
		(layers "F.Cu" "B.Cu")
		(net "GND")
	)
	(via
		(at 435.823614 -229.616762)
		(size 0.4572)
		(drill 0.2032)
		(layers "F.Cu" "B.Cu")
		(net "GND")
	)
	(via
		(at 94.833694 -273.453098)
		(size 0.4572)
		(drill 0.2032)
		(layers "F.Cu" "B.Cu")
		(net "GND")
	)
	(via
		(at 388.349998 -438.499758)
		(size 0.4572)
		(drill 0.2032)
		(layers "F.Cu" "B.Cu")
		(net "GND")
	)
	(via
		(at 96.78924 -364.139988)
		(size 0.508)
		(drill 0.254)
		(layers "F.Cu" "B.Cu")
		(net "GND")
	)
	(via
		(at 236.279182 -249.757692)
		(size 0.508)
		(drill 0.254)
		(layers "F.Cu" "B.Cu")
		(net "GND")
	)
	(via
		(at 171.715684 -319.522856)
		(size 0.4572)
		(drill 0.2032)
		(layers "F.Cu" "B.Cu")
		(net "GND")
	)
	(via
		(at 287.360614 -201.56678)
		(size 0.4572)
		(drill 0.2032)
		(layers "F.Cu" "B.Cu")
		(net "GND")
	)
	(via
		(at 307.782214 -227.066602)
		(size 0.4572)
		(drill 0.2032)
		(layers "F.Cu" "B.Cu")
		(net "GND")
	)
	(via
		(at 187.462922 -17.655032)
		(size 0.508)
		(drill 0.254)
		(layers "F.Cu" "B.Cu")
		(net "GND")
	)
	(via
		(at 122.917712 -234.15625)
		(size 0.4572)
		(drill 0.2032)
		(layers "F.Cu" "B.Cu")
		(net "GND")
	)
	(via
		(at 361.277916 -333.355188)
		(size 0.49022)
		(drill 0.254)
		(layers "F.Cu" "B.Cu")
		(net "GND")
	)
	(via
		(at 279.816814 -244.916706)
		(size 0.4572)
		(drill 0.2032)
		(layers "F.Cu" "B.Cu")
		(net "GND")
	)
	(via
		(at 76.250038 -430.299622)
		(size 0.4572)
		(drill 0.2032)
		(layers "F.Cu" "B.Cu")
		(net "GND")
	)
	(via
		(at 276.373082 -239.81664)
		(size 0.4572)
		(drill 0.2032)
		(layers "F.Cu" "B.Cu")
		(net "GND")
	)
	(via
		(at 300.238414 -315.46673)
		(size 0.4572)
		(drill 0.2032)
		(layers "F.Cu" "B.Cu")
		(net "GND")
	)
	(via
		(at 363.373416 -252.805692)
		(size 0.4572)
		(drill 0.2032)
		(layers "F.Cu" "B.Cu")
		(net "GND")
	)
	(via
		(at 87.671656 -79.815436)
		(size 0.508)
		(drill 0.254)
		(layers "F.Cu" "B.Cu")
		(net "GND")
	)
	(via
		(at 160.69056 -27.313128)
		(size 0.508)
		(drill 0.254)
		(layers "F.Cu" "B.Cu")
		(net "GND")
	)
	(via
		(at 279.816814 -278.066754)
		(size 0.4572)
		(drill 0.2032)
		(layers "F.Cu" "B.Cu")
		(net "GND")
	)
	(via
		(at 266.619482 -299.316648)
		(size 0.4572)
		(drill 0.2032)
		(layers "F.Cu" "B.Cu")
		(net "GND")
	)
	(via
		(at 69.095366 -112.70869)
		(size 0.508)
		(drill 0.254)
		(layers "F.Cu" "B.Cu")
		(net "GND")
	)
	(via
		(at 420.736014 -242.3668)
		(size 0.4572)
		(drill 0.2032)
		(layers "F.Cu" "B.Cu")
		(net "GND")
	)
	(via
		(at 287.360614 -244.916706)
		(size 0.4572)
		(drill 0.2032)
		(layers "F.Cu" "B.Cu")
		(net "GND")
	)
	(via
		(at 371.327934 -220.319854)
		(size 0.4572)
		(drill 0.2032)
		(layers "F.Cu" "B.Cu")
		(net "GND")
	)
	(via
		(at 72.771 -13.325348)
		(size 0.508)
		(drill 0.254)
		(layers "F.Cu" "B.Cu")
		(net "GND")
	)
	(via
		(at 113.629948 -260.431026)
		(size 0.4572)
		(drill 0.2032)
		(layers "F.Cu" "B.Cu")
		(net "GND")
	)
	(via
		(at 381.665734 -244.73662)
		(size 0.4572)
		(drill 0.2032)
		(layers "F.Cu" "B.Cu")
		(net "GND")
	)
	(via
		(at 391.102596 -18.235422)
		(size 0.508)
		(drill 0.254)
		(layers "F.Cu" "B.Cu")
		(net "GND")
	)
	(via
		(at 195.427346 -214.316564)
		(size 0.4572)
		(drill 0.2032)
		(layers "F.Cu" "B.Cu")
		(net "GND")
	)
	(via
		(at 262.519414 -217.716608)
		(size 0.4572)
		(drill 0.2032)
		(layers "F.Cu" "B.Cu")
		(net "GND")
	)
	(via
		(at 335.255362 -255.547622)
		(size 0.4572)
		(drill 0.2032)
		(layers "F.Cu" "B.Cu")
		(net "GND")
	)
	(via
		(at 76.250038 -429.147224)
		(size 0.4572)
		(drill 0.2032)
		(layers "F.Cu" "B.Cu")
		(net "GND")
	)
	(via
		(at 126.350014 -438.651396)
		(size 0.4572)
		(drill 0.2032)
		(layers "F.Cu" "B.Cu")
		(net "GND")
	)
	(via
		(at 99.36353 -93.522546)
		(size 0.508)
		(drill 0.254)
		(layers "F.Cu" "B.Cu")
		(net "GND")
	)
	(via
		(at 281.707082 -222.816674)
		(size 0.4572)
		(drill 0.2032)
		(layers "F.Cu" "B.Cu")
		(net "GND")
	)
	(via
		(at 311.666382 -228.766624)
		(size 0.4572)
		(drill 0.2032)
		(layers "F.Cu" "B.Cu")
		(net "GND")
	)
	(via
		(at 264.394696 -72.662542)
		(size 0.508)
		(drill 0.254)
		(layers "F.Cu" "B.Cu")
		(net "GND")
	)
	(via
		(at 64.444626 -407.638504)
		(size 0.4572)
		(drill 0.254)
		(layers "F.Cu" "B.Cu")
		(net "GND")
	)
	(via
		(at 409.748482 -294.216582)
		(size 0.4572)
		(drill 0.2032)
		(layers "F.Cu" "B.Cu")
		(net "GND")
	)
	(via
		(at 294.904414 -290.816792)
		(size 0.4572)
		(drill 0.2032)
		(layers "F.Cu" "B.Cu")
		(net "GND")
	)
	(via
		(at 209.281014 -230.466646)
		(size 0.4572)
		(drill 0.2032)
		(layers "F.Cu" "B.Cu")
		(net "GND")
	)
	(via
		(at 139.682982 -406.34666)
		(size 0.4572)
		(drill 0.254)
		(layers "F.Cu" "B.Cu")
		(net "GND")
	)
	(via
		(at 207.071214 -241.516662)
		(size 0.4572)
		(drill 0.2032)
		(layers "F.Cu" "B.Cu")
		(net "GND")
	)
	(via
		(at 212.724746 -307.816758)
		(size 0.4572)
		(drill 0.2032)
		(layers "F.Cu" "B.Cu")
		(net "GND")
	)
	(via
		(at 209.281014 -205.816708)
		(size 0.4572)
		(drill 0.2032)
		(layers "F.Cu" "B.Cu")
		(net "GND")
	)
	(via
		(at 285.150814 -295.06672)
		(size 0.4572)
		(drill 0.2032)
		(layers "F.Cu" "B.Cu")
		(net "GND")
	)
	(via
		(at 79.80045 -343.48293)
		(size 0.49022)
		(drill 0.254)
		(layers "F.Cu" "B.Cu")
		(net "GND")
	)
	(via
		(at 443.367414 -195.616576)
		(size 0.4572)
		(drill 0.2032)
		(layers "F.Cu" "B.Cu")
		(net "GND")
	)
	(via
		(at 422.945814 -199.01662)
		(size 0.4572)
		(drill 0.2032)
		(layers "F.Cu" "B.Cu")
		(net "GND")
	)
	(via
		(at 342.773762 -279.964134)
		(size 0.4572)
		(drill 0.2032)
		(layers "F.Cu" "B.Cu")
		(net "GND")
	)
	(via
		(at 202.971146 -267.016738)
		(size 0.4572)
		(drill 0.2032)
		(layers "F.Cu" "B.Cu")
		(net "GND")
	)
	(via
		(at 447.467482 -301.01667)
		(size 0.4572)
		(drill 0.2032)
		(layers "F.Cu" "B.Cu")
		(net "GND")
	)
	(via
		(at 186.649614 -221.116652)
		(size 0.4572)
		(drill 0.2032)
		(layers "F.Cu" "B.Cu")
		(net "GND")
	)
	(via
		(at 396.390114 -5.585714)
		(size 0.508)
		(drill 0.254)
		(layers "F.Cu" "B.Cu")
		(net "GND")
	)
	(via
		(at 138.534394 -285.661354)
		(size 0.4572)
		(drill 0.2032)
		(layers "F.Cu" "B.Cu")
		(net "GND")
	)
	(via
		(at 321.22999 -44.578524)
		(size 0.508)
		(drill 0.254)
		(layers "F.Cu" "B.Cu")
		(net "GND")
	)
	(via
		(at 16.812006 -319.401952)
		(size 0.4572)
		(drill 0.2032)
		(layers "F.Cu" "B.Cu")
		(net "GND")
	)
	(via
		(at 87.211916 -98.548952)
		(size 0.508)
		(drill 0.254)
		(layers "F.Cu" "B.Cu")
		(net "GND")
	)
	(via
		(at 90.964766 -216.25052)
		(size 0.4572)
		(drill 0.2032)
		(layers "F.Cu" "B.Cu")
		(net "GND")
	)
	(via
		(at 62.051946 -298.466764)
		(size 0.4572)
		(drill 0.2032)
		(layers "F.Cu" "B.Cu")
		(net "GND")
	)
	(via
		(at 422.945814 -210.916774)
		(size 0.4572)
		(drill 0.2032)
		(layers "F.Cu" "B.Cu")
		(net "GND")
	)
	(via
		(at 337.604862 -279.150318)
		(size 0.4572)
		(drill 0.2032)
		(layers "F.Cu" "B.Cu")
		(net "GND")
	)
	(via
		(at 57.852818 -170.689524)
		(size 0.508)
		(drill 0.254)
		(layers "F.Cu" "B.Cu")
		(net "GND")
	)
	(via
		(at 118.169944 -74.631042)
		(size 0.508)
		(drill 0.254)
		(layers "F.Cu" "B.Cu")
		(net "GND")
	)
	(via
		(at 409.748482 -232.166668)
		(size 0.4572)
		(drill 0.2032)
		(layers "F.Cu" "B.Cu")
		(net "GND")
	)
	(via
		(at 126.350014 -436.347362)
		(size 0.4572)
		(drill 0.2032)
		(layers "F.Cu" "B.Cu")
		(net "GND")
	)
	(via
		(at 453.121014 -298.466764)
		(size 0.4572)
		(drill 0.2032)
		(layers "F.Cu" "B.Cu")
		(net "GND")
	)
	(via
		(at 420.736014 -295.06672)
		(size 0.4572)
		(drill 0.2032)
		(layers "F.Cu" "B.Cu")
		(net "GND")
	)
	(via
		(at 460.664814 -313.766708)
		(size 0.4572)
		(drill 0.2032)
		(layers "F.Cu" "B.Cu")
		(net "GND")
	)
	(via
		(at 233.09072 -43.687746)
		(size 0.508)
		(drill 0.254)
		(layers "F.Cu" "B.Cu")
		(net "GND")
	)
	(via
		(at 214.615014 -241.516662)
		(size 0.4572)
		(drill 0.2032)
		(layers "F.Cu" "B.Cu")
		(net "GND")
	)
	(via
		(at 178.925982 -421.122856)
		(size 0.508)
		(drill 0.254)
		(layers "F.Cu" "B.Cu")
		(net "GND")
	)
	(via
		(at 119.628666 -223.575626)
		(size 0.4572)
		(drill 0.2032)
		(layers "F.Cu" "B.Cu")
		(net "GND")
	)
	(via
		(at 417.581588 -17.601438)
		(size 0.508)
		(drill 0.254)
		(layers "F.Cu" "B.Cu")
		(net "GND")
	)
	(via
		(at 306.751482 -235.566712)
		(size 0.4572)
		(drill 0.2032)
		(layers "F.Cu" "B.Cu")
		(net "GND")
	)
	(via
		(at 449.677282 -297.616626)
		(size 0.4572)
		(drill 0.2032)
		(layers "F.Cu" "B.Cu")
		(net "GND")
	)
	(via
		(at 337.024726 -214.622634)
		(size 0.4572)
		(drill 0.2032)
		(layers "F.Cu" "B.Cu")
		(net "GND")
	)
	(via
		(at 268.829282 -269.566644)
		(size 0.4572)
		(drill 0.2032)
		(layers "F.Cu" "B.Cu")
		(net "GND")
	)
	(via
		(at 161.808414 -196.466714)
		(size 0.4572)
		(drill 0.2032)
		(layers "F.Cu" "B.Cu")
		(net "GND")
	)
	(via
		(at 307.782214 -214.316564)
		(size 0.4572)
		(drill 0.2032)
		(layers "F.Cu" "B.Cu")
		(net "GND")
	)
	(via
		(at 344.54338 -247.178322)
		(size 0.4572)
		(drill 0.2032)
		(layers "F.Cu" "B.Cu")
		(net "GND")
	)
	(via
		(at 458.455014 -204.96657)
		(size 0.4572)
		(drill 0.2032)
		(layers "F.Cu" "B.Cu")
		(net "GND")
	)
	(via
		(at 82.482182 -37.743892)
		(size 0.508)
		(drill 0.254)
		(layers "F.Cu" "B.Cu")
		(net "GND")
	)
	(via
		(at 414.070292 -170.192954)
		(size 0.49022)
		(drill 0.254)
		(layers "F.Cu" "B.Cu")
		(net "GND")
	)
	(via
		(at 349.24238 -248.806208)
		(size 0.4572)
		(drill 0.2032)
		(layers "F.Cu" "B.Cu")
		(net "GND")
	)
	(via
		(at 210.514946 -315.46673)
		(size 0.4572)
		(drill 0.2032)
		(layers "F.Cu" "B.Cu")
		(net "GND")
	)
	(via
		(at 184.20588 -96.719898)
		(size 0.508)
		(drill 0.254)
		(layers "F.Cu" "B.Cu")
		(net "GND")
	)
	(via
		(at 287.835086 -354.868226)
		(size 0.508)
		(drill 0.254)
		(layers "F.Cu" "B.Cu")
		(net "GND")
	)
	(via
		(at 401.49653 -400.858228)
		(size 0.4064)
		(drill 0.2032)
		(layers "F.Cu" "B.Cu")
		(net "GND")
	)
	(via
		(at 350.80956 -260.812534)
		(size 0.4572)
		(drill 0.2032)
		(layers "F.Cu" "B.Cu")
		(net "GND")
	)
	(via
		(at 347.473016 -262.058658)
		(size 0.4572)
		(drill 0.2032)
		(layers "F.Cu" "B.Cu")
		(net "GND")
	)
	(via
		(at 464.44154 -387.58241)
		(size 0.508)
		(drill 0.254)
		(layers "F.Cu" "B.Cu")
		(net "GND")
	)
	(via
		(at 420.736014 -292.516814)
		(size 0.4572)
		(drill 0.2032)
		(layers "F.Cu" "B.Cu")
		(net "GND")
	)
	(via
		(at 113.67008 -123.148598)
		(size 0.508)
		(drill 0.254)
		(layers "F.Cu" "B.Cu")
		(net "GND")
	)
	(via
		(at 299.004482 -306.96662)
		(size 0.4572)
		(drill 0.2032)
		(layers "F.Cu" "B.Cu")
		(net "GND")
	)
	(via
		(at 165.024054 -313.766708)
		(size 0.4572)
		(drill 0.2032)
		(layers "F.Cu" "B.Cu")
		(net "GND")
	)
	(via
		(at 341.887556 -410.664152)
		(size 0.4572)
		(drill 0.254)
		(layers "F.Cu" "B.Cu")
		(net "GND")
	)
	(via
		(at 14.579346 -223.666558)
		(size 0.4572)
		(drill 0.2032)
		(layers "F.Cu" "B.Cu")
		(net "GND")
	)
	(via
		(at 18.679414 -308.666642)
		(size 0.4572)
		(drill 0.2032)
		(layers "F.Cu" "B.Cu")
		(net "GND")
	)
	(via
		(at 14.579346 -301.866808)
		(size 0.4572)
		(drill 0.2032)
		(layers "F.Cu" "B.Cu")
		(net "GND")
	)
	(via
		(at 424.836082 -204.116686)
		(size 0.4572)
		(drill 0.2032)
		(layers "F.Cu" "B.Cu")
		(net "GND")
	)
	(via
		(at 383.655062 -275.8948)
		(size 0.4572)
		(drill 0.2032)
		(layers "F.Cu" "B.Cu")
		(net "GND")
	)
	(via
		(at 374.14708 -241.481102)
		(size 0.4572)
		(drill 0.2032)
		(layers "F.Cu" "B.Cu")
		(net "GND")
	)
	(via
		(at 28.638246 -393.342876)
		(size 0.508)
		(drill 0.254)
		(layers "F.Cu" "B.Cu")
		(net "GND")
	)
	(via
		(at 449.013072 -0.76454)
		(size 0.508)
		(drill 0.254)
		(layers "F.Cu" "B.Cu")
		(net "GND")
	)
	(via
		(at 176.155604 -112.57534)
		(size 0.4572)
		(drill 0.254)
		(layers "F.Cu" "B.Cu")
		(net "GND")
	)
	(via
		(at 215.97112 -28.918408)
		(size 0.508)
		(drill 0.254)
		(layers "F.Cu" "B.Cu")
		(net "GND")
	)
	(via
		(at 98.122994 -275.8948)
		(size 0.4572)
		(drill 0.2032)
		(layers "F.Cu" "B.Cu")
		(net "GND")
	)
	(via
		(at 76.61021 -400.224244)
		(size 0.4572)
		(drill 0.254)
		(layers "F.Cu" "B.Cu")
		(net "GND")
	)
	(via
		(at 210.514946 -242.3668)
		(size 0.4572)
		(drill 0.2032)
		(layers "F.Cu" "B.Cu")
		(net "GND")
	)
	(via
		(at 348.882716 -256.361438)
		(size 0.4572)
		(drill 0.2032)
		(layers "F.Cu" "B.Cu")
		(net "GND")
	)
	(via
		(at 345.013534 -220.319854)
		(size 0.4572)
		(drill 0.2032)
		(layers "F.Cu" "B.Cu")
		(net "GND")
	)
	(via
		(at 311.882282 -306.96662)
		(size 0.4572)
		(drill 0.2032)
		(layers "F.Cu" "B.Cu")
		(net "GND")
	)
	(via
		(at 66.152014 -267.866622)
		(size 0.4572)
		(drill 0.2032)
		(layers "F.Cu" "B.Cu")
		(net "GND")
	)
	(via
		(at 285.150814 -251.716794)
		(size 0.4572)
		(drill 0.2032)
		(layers "F.Cu" "B.Cu")
		(net "GND")
	)
	(via
		(at 43.85691 -10.16508)
		(size 0.508)
		(drill 0.254)
		(layers "F.Cu" "B.Cu")
		(net "GND")
	)
	(via
		(at 55.260494 -147.861274)
		(size 0.49022)
		(drill 0.254)
		(layers "F.Cu" "B.Cu")
		(net "GND")
	)
	(via
		(at 377.333256 -337.692238)
		(size 0.49022)
		(drill 0.254)
		(layers "F.Cu" "B.Cu")
		(net "GND")
	)
	(via
		(at 70.48373 -401.492212)
		(size 0.4572)
		(drill 0.254)
		(layers "F.Cu" "B.Cu")
		(net "GND")
	)
	(via
		(at 2.764536 -269.670022)
		(size 0.508)
		(drill 0.254)
		(layers "F.Cu" "B.Cu")
		(net "GND")
	)
	(via
		(at 386.083302 -410.664152)
		(size 0.4572)
		(drill 0.254)
		(layers "F.Cu" "B.Cu")
		(net "GND")
	)
	(via
		(at 322.161916 -400.200368)
		(size 0.4572)
		(drill 0.254)
		(layers "F.Cu" "B.Cu")
		(net "GND")
	)
	(via
		(at 81.01965 -407.638504)
		(size 0.4572)
		(drill 0.254)
		(layers "F.Cu" "B.Cu")
		(net "GND")
	)
	(via
		(at 374.726962 -260.430772)
		(size 0.4572)
		(drill 0.2032)
		(layers "F.Cu" "B.Cu")
		(net "GND")
	)
	(via
		(at 180.339746 -295.06672)
		(size 0.4572)
		(drill 0.2032)
		(layers "F.Cu" "B.Cu")
		(net "GND")
	)
	(via
		(at 298.21759 -363.337094)
		(size 0.49022)
		(drill 0.254)
		(layers "F.Cu" "B.Cu")
		(net "GND")
	)
	(via
		(at 464.764882 -284.866588)
		(size 0.4572)
		(drill 0.2032)
		(layers "F.Cu" "B.Cu")
		(net "GND")
	)
	(via
		(at 46.393862 -356.75189)
		(size 0.508)
		(drill 0.254)
		(layers "F.Cu" "B.Cu")
		(net "GND")
	)
	(via
		(at 112.694212 -37.01034)
		(size 0.508)
		(drill 0.254)
		(layers "F.Cu" "B.Cu")
		(net "GND")
	)
	(via
		(at 136.448038 -341.766906)
		(size 0.49022)
		(drill 0.254)
		(layers "F.Cu" "B.Cu")
		(net "GND")
	)
	(via
		(at 430.186592 -117.785896)
		(size 0.508)
		(drill 0.254)
		(layers "F.Cu" "B.Cu")
		(net "GND")
	)
	(via
		(at 161.550604 -235.566712)
		(size 0.4572)
		(drill 0.2032)
		(layers "F.Cu" "B.Cu")
		(net "GND")
	)
	(via
		(at 124.437394 -262.872474)
		(size 0.4572)
		(drill 0.2032)
		(layers "F.Cu" "B.Cu")
		(net "GND")
	)
	(via
		(at 434.589682 -216.866724)
		(size 0.4572)
		(drill 0.2032)
		(layers "F.Cu" "B.Cu")
		(net "GND")
	)
	(via
		(at 449.677282 -198.166736)
		(size 0.4572)
		(drill 0.2032)
		(layers "F.Cu" "B.Cu")
		(net "GND")
	)
	(via
		(at 102.822248 -280.778204)
		(size 0.4572)
		(drill 0.2032)
		(layers "F.Cu" "B.Cu")
		(net "GND")
	)
	(via
		(at 176.896014 -306.96662)
		(size 0.4572)
		(drill 0.2032)
		(layers "F.Cu" "B.Cu")
		(net "GND")
	)
	(via
		(at 45.093128 -350.214438)
		(size 0.508)
		(drill 0.254)
		(layers "F.Cu" "B.Cu")
		(net "GND")
	)
	(via
		(at 59.842146 -195.616576)
		(size 0.4572)
		(drill 0.2032)
		(layers "F.Cu" "B.Cu")
		(net "GND")
	)
	(via
		(at 361.569762 -271.825212)
		(size 0.4572)
		(drill 0.2032)
		(layers "F.Cu" "B.Cu")
		(net "GND")
	)
	(via
		(at 96.243394 -261.244842)
		(size 0.4572)
		(drill 0.2032)
		(layers "F.Cu" "B.Cu")
		(net "GND")
	)
	(via
		(at 283.99994 -355.09454)
		(size 0.508)
		(drill 0.254)
		(layers "F.Cu" "B.Cu")
		(net "GND")
	)
	(via
		(at 80.25003 -431.451258)
		(size 0.4572)
		(drill 0.2032)
		(layers "F.Cu" "B.Cu")
		(net "GND")
	)
	(via
		(at 310.032654 -322.499736)
		(size 0.4572)
		(drill 0.2032)
		(layers "F.Cu" "B.Cu")
		(net "GND")
	)
	(via
		(at 63.942214 -215.166702)
		(size 0.4572)
		(drill 0.2032)
		(layers "F.Cu" "B.Cu")
		(net "GND")
	)
	(via
		(at 99.286568 -103.343202)
		(size 0.508)
		(drill 0.254)
		(layers "F.Cu" "B.Cu")
		(net "GND")
	)
	(via
		(at 378.956062 -284.033722)
		(size 0.4572)
		(drill 0.2032)
		(layers "F.Cu" "B.Cu")
		(net "GND")
	)
	(via
		(at 218.651582 -70.311518)
		(size 0.508)
		(drill 0.254)
		(layers "F.Cu" "B.Cu")
		(net "GND")
	)
	(via
		(at 120.97639 -245.599204)
		(size 0.4572)
		(drill 0.2032)
		(layers "F.Cu" "B.Cu")
		(net "GND")
	)
	(via
		(at 423.195242 -390.616948)
		(size 0.508)
		(drill 0.254)
		(layers "F.Cu" "B.Cu")
		(net "GND")
	)
	(via
		(at 354.003864 -257.692906)
		(size 0.4572)
		(drill 0.2032)
		(layers "F.Cu" "B.Cu")
		(net "GND")
	)
	(via
		(at 23.041102 -402.806408)
		(size 0.508)
		(drill 0.254)
		(layers "F.Cu" "B.Cu")
		(net "GND")
	)
	(via
		(at 59.842146 -204.96657)
		(size 0.4572)
		(drill 0.2032)
		(layers "F.Cu" "B.Cu")
		(net "GND")
	)
	(via
		(at 435.823614 -307.816758)
		(size 0.4572)
		(drill 0.2032)
		(layers "F.Cu" "B.Cu")
		(net "GND")
	)
	(via
		(at 154.911806 -401.492212)
		(size 0.4572)
		(drill 0.254)
		(layers "F.Cu" "B.Cu")
		(net "GND")
	)
	(via
		(at 402.84273 -410.030168)
		(size 0.4064)
		(drill 0.2032)
		(layers "F.Cu" "B.Cu")
		(net "GND")
	)
	(via
		(at 414.808162 -360.937556)
		(size 0.49022)
		(drill 0.254)
		(layers "F.Cu" "B.Cu")
		(net "GND")
	)
	(via
		(at 56.398414 -247.466612)
		(size 0.4572)
		(drill 0.2032)
		(layers "F.Cu" "B.Cu")
		(net "GND")
	)
	(via
		(at 285.150814 -201.56678)
		(size 0.4572)
		(drill 0.2032)
		(layers "F.Cu" "B.Cu")
		(net "GND")
	)
	(via
		(at 428.279814 -268.71676)
		(size 0.4572)
		(drill 0.2032)
		(layers "F.Cu" "B.Cu")
		(net "GND")
	)
	(via
		(at 96.243394 -267.755878)
		(size 0.4572)
		(drill 0.2032)
		(layers "F.Cu" "B.Cu")
		(net "GND")
	)
	(via
		(at 426.075856 -124.91466)
		(size 0.508)
		(drill 0.254)
		(layers "F.Cu" "B.Cu")
		(net "GND")
	)
	(via
		(at 114.78514 -417.393628)
		(size 0.508)
		(drill 0.254)
		(layers "F.Cu" "B.Cu")
		(net "GND")
	)
	(via
		(at 91.704922 -331.852524)
		(size 0.508)
		(drill 0.254)
		(layers "F.Cu" "B.Cu")
		(net "GND")
	)
	(via
		(at 140.941806 -409.396184)
		(size 0.4572)
		(drill 0.254)
		(layers "F.Cu" "B.Cu")
		(net "GND")
	)
	(via
		(at 199.527414 -295.916604)
		(size 0.4572)
		(drill 0.2032)
		(layers "F.Cu" "B.Cu")
		(net "GND")
	)
	(via
		(at 134.305294 -286.475424)
		(size 0.4572)
		(drill 0.2032)
		(layers "F.Cu" "B.Cu")
		(net "GND")
	)
	(via
		(at 56.51373 -407.638504)
		(size 0.4572)
		(drill 0.254)
		(layers "F.Cu" "B.Cu")
		(net "GND")
	)
	(via
		(at 84.179918 -400.858228)
		(size 0.4064)
		(drill 0.2032)
		(layers "F.Cu" "B.Cu")
		(net "GND")
	)
	(via
		(at 348.412816 -255.547622)
		(size 0.4572)
		(drill 0.2032)
		(layers "F.Cu" "B.Cu")
		(net "GND")
	)
	(via
		(at 448.48018 -116.335048)
		(size 0.508)
		(drill 0.254)
		(layers "F.Cu" "B.Cu")
		(net "GND")
	)
	(via
		(at 425.96689 -7.215124)
		(size 0.508)
		(drill 0.254)
		(layers "F.Cu" "B.Cu")
		(net "GND")
	)
	(via
		(at 283.916882 -249.166634)
		(size 0.4572)
		(drill 0.2032)
		(layers "F.Cu" "B.Cu")
		(net "GND")
	)
	(via
		(at 35.976814 -271.266666)
		(size 0.4572)
		(drill 0.2032)
		(layers "F.Cu" "B.Cu")
		(net "GND")
	)
	(via
		(at 119.738394 -284.033722)
		(size 0.4572)
		(drill 0.2032)
		(layers "F.Cu" "B.Cu")
		(net "GND")
	)
	(via
		(at 380.366016 -258.80314)
		(size 0.4572)
		(drill 0.2032)
		(layers "F.Cu" "B.Cu")
		(net "GND")
	)
	(via
		(at 106.471466 -213.732618)
		(size 0.4572)
		(drill 0.2032)
		(layers "F.Cu" "B.Cu")
		(net "GND")
	)
	(via
		(at 175.005746 -276.366732)
		(size 0.4572)
		(drill 0.2032)
		(layers "F.Cu" "B.Cu")
		(net "GND")
	)
	(via
		(at 33.767014 -295.916604)
		(size 0.4572)
		(drill 0.2032)
		(layers "F.Cu" "B.Cu")
		(net "GND")
	)
	(via
		(at 20.889214 -312.91657)
		(size 0.4572)
		(drill 0.2032)
		(layers "F.Cu" "B.Cu")
		(net "GND")
	)
	(via
		(at 285.150814 -248.31675)
		(size 0.4572)
		(drill 0.2032)
		(layers "F.Cu" "B.Cu")
		(net "GND")
	)
	(via
		(at 449.584318 -183.17845)
		(size 0.6604)
		(drill 0.3302)
		(layers "F.Cu" "B.Cu")
		(net "GND")
	)
	(via
		(at 462.555082 -312.91657)
		(size 0.4572)
		(drill 0.2032)
		(layers "F.Cu" "B.Cu")
		(net "GND")
	)
	(via
		(at 41.310814 -210.066636)
		(size 0.4572)
		(drill 0.2032)
		(layers "F.Cu" "B.Cu")
		(net "GND")
	)
	(via
		(at 386.004816 -283.219906)
		(size 0.4572)
		(drill 0.2032)
		(layers "F.Cu" "B.Cu")
		(net "GND")
	)
	(via
		(at 360.520234 -222.761556)
		(size 0.4572)
		(drill 0.2032)
		(layers "F.Cu" "B.Cu")
		(net "GND")
	)
	(via
		(at 13.67155 -107.123484)
		(size 0.508)
		(drill 0.254)
		(layers "F.Cu" "B.Cu")
		(net "GND")
	)
	(via
		(at 2.764536 -315.390022)
		(size 0.508)
		(drill 0.254)
		(layers "F.Cu" "B.Cu")
		(net "GND")
	)
	(via
		(at 389.630158 -76.566776)
		(size 0.6604)
		(drill 0.3302)
		(layers "F.Cu" "B.Cu")
		(net "GND")
	)
	(via
		(at 420.736014 -289.11677)
		(size 0.4572)
		(drill 0.2032)
		(layers "F.Cu" "B.Cu")
		(net "GND")
	)
	(via
		(at 415.456878 -407.638504)
		(size 0.4572)
		(drill 0.254)
		(layers "F.Cu" "B.Cu")
		(net "GND")
	)
	(via
		(at 307.782214 -267.016738)
		(size 0.4572)
		(drill 0.2032)
		(layers "F.Cu" "B.Cu")
		(net "GND")
	)
	(via
		(at 344.691208 -334.282034)
		(size 0.49022)
		(drill 0.254)
		(layers "F.Cu" "B.Cu")
		(net "GND")
	)
	(via
		(at 86.735412 -234.970066)
		(size 0.4318)
		(drill 0.2032)
		(layers "F.Cu" "B.Cu")
		(net "GND")
	)
	(via
		(at 458.455014 -278.066754)
		(size 0.4572)
		(drill 0.2032)
		(layers "F.Cu" "B.Cu")
		(net "GND")
	)
	(via
		(at 100.832666 -223.575626)
		(size 0.4572)
		(drill 0.2032)
		(layers "F.Cu" "B.Cu")
		(net "GND")
	)
	(via
		(at 123.027694 -289.807142)
		(size 0.4572)
		(drill 0.2032)
		(layers "F.Cu" "B.Cu")
		(net "GND")
	)
	(via
		(at 390.198864 -77.954886)
		(size 0.508)
		(drill 0.254)
		(layers "F.Cu" "B.Cu")
		(net "GND")
	)
	(via
		(at 372.26748 -234.970066)
		(size 0.4572)
		(drill 0.2032)
		(layers "F.Cu" "B.Cu")
		(net "GND")
	)
	(via
		(at 107.881166 -226.017328)
		(size 0.4572)
		(drill 0.2032)
		(layers "F.Cu" "B.Cu")
		(net "GND")
	)
	(via
		(at 124.652786 -328.162412)
		(size 0.508)
		(drill 0.254)
		(layers "F.Cu" "B.Cu")
		(net "GND")
	)
	(via
		(at 376.966734 -231.714548)
		(size 0.4572)
		(drill 0.2032)
		(layers "F.Cu" "B.Cu")
		(net "GND")
	)
	(via
		(at 179.105814 -267.866622)
		(size 0.4572)
		(drill 0.2032)
		(layers "F.Cu" "B.Cu")
		(net "GND")
	)
	(via
		(at 289.250882 -245.76659)
		(size 0.4572)
		(drill 0.2032)
		(layers "F.Cu" "B.Cu")
		(net "GND")
	)
	(via
		(at 55.528718 -403.883876)
		(size 0.4064)
		(drill 0.2032)
		(layers "F.Cu" "B.Cu")
		(net "GND")
	)
	(via
		(at 54.508146 -263.616694)
		(size 0.4572)
		(drill 0.2032)
		(layers "F.Cu" "B.Cu")
		(net "GND")
	)
	(via
		(at 415.456878 -410.664152)
		(size 0.4572)
		(drill 0.254)
		(layers "F.Cu" "B.Cu")
		(net "GND")
	)
	(via
		(at 94.98965 -403.249892)
		(size 0.4572)
		(drill 0.254)
		(layers "F.Cu" "B.Cu")
		(net "GND")
	)
	(via
		(at 443.367414 -300.166786)
		(size 0.4572)
		(drill 0.2032)
		(layers "F.Cu" "B.Cu")
		(net "GND")
	)
	(via
		(at 194.193414 -194.766692)
		(size 0.4572)
		(drill 0.2032)
		(layers "F.Cu" "B.Cu")
		(net "GND")
	)
	(via
		(at 287.360614 -220.266768)
		(size 0.4572)
		(drill 0.2032)
		(layers "F.Cu" "B.Cu")
		(net "GND")
	)
	(via
		(at 299.916088 -360.83621)
		(size 0.49022)
		(drill 0.254)
		(layers "F.Cu" "B.Cu")
		(net "GND")
	)
	(via
		(at 300.238414 -290.816792)
		(size 0.4572)
		(drill 0.2032)
		(layers "F.Cu" "B.Cu")
		(net "GND")
	)
	(via
		(at 368.727228 -332.56601)
		(size 0.49022)
		(drill 0.254)
		(layers "F.Cu" "B.Cu")
		(net "GND")
	)
	(via
		(at 184.439814 -196.466714)
		(size 0.4572)
		(drill 0.2032)
		(layers "F.Cu" "B.Cu")
		(net "GND")
	)
	(via
		(at 292.694614 -272.116804)
		(size 0.4572)
		(drill 0.2032)
		(layers "F.Cu" "B.Cu")
		(net "GND")
	)
	(via
		(at 13.345414 -216.866724)
		(size 0.4572)
		(drill 0.2032)
		(layers "F.Cu" "B.Cu")
		(net "GND")
	)
	(via
		(at 159.918146 -289.11677)
		(size 0.4572)
		(drill 0.2032)
		(layers "F.Cu" "B.Cu")
		(net "GND")
	)
	(via
		(at 23.037292 -416.143948)
		(size 0.508)
		(drill 0.254)
		(layers "F.Cu" "B.Cu")
		(net "GND")
	)
	(via
		(at 46.964346 -283.166566)
		(size 0.4572)
		(drill 0.2032)
		(layers "F.Cu" "B.Cu")
		(net "GND")
	)
	(via
		(at 61.29401 -403.249892)
		(size 0.4572)
		(drill 0.254)
		(layers "F.Cu" "B.Cu")
		(net "GND")
	)
	(via
		(at 347.942662 -257.98907)
		(size 0.4572)
		(drill 0.2032)
		(layers "F.Cu" "B.Cu")
		(net "GND")
	)
	(via
		(at 87.14613 -406.370536)
		(size 0.4572)
		(drill 0.254)
		(layers "F.Cu" "B.Cu")
		(net "GND")
	)
	(via
		(at 121.148348 -281.59202)
		(size 0.4572)
		(drill 0.2032)
		(layers "F.Cu" "B.Cu")
		(net "GND")
	)
	(via
		(at 292.694614 -246.616728)
		(size 0.4572)
		(drill 0.2032)
		(layers "F.Cu" "B.Cu")
		(net "GND")
	)
	(via
		(at 405.648414 -309.51678)
		(size 0.4572)
		(drill 0.2032)
		(layers "F.Cu" "B.Cu")
		(net "GND")
	)
	(via
		(at 46.964346 -268.71676)
		(size 0.4572)
		(drill 0.2032)
		(layers "F.Cu" "B.Cu")
		(net "GND")
	)
	(via
		(at 66.152014 -228.766624)
		(size 0.4572)
		(drill 0.2032)
		(layers "F.Cu" "B.Cu")
		(net "GND")
	)
	(via
		(at 332.43266 -73.703688)
		(size 0.508)
		(drill 0.254)
		(layers "F.Cu" "B.Cu")
		(net "GND")
	)
	(via
		(at 133.843014 -113.741708)
		(size 0.508)
		(drill 0.254)
		(layers "F.Cu" "B.Cu")
		(net "GND")
	)
	(via
		(at 289.250882 -312.91657)
		(size 0.4572)
		(drill 0.2032)
		(layers "F.Cu" "B.Cu")
		(net "GND")
	)
	(via
		(at 69.250052 -430.147222)
		(size 0.4572)
		(drill 0.2032)
		(layers "F.Cu" "B.Cu")
		(net "GND")
	)
	(via
		(at 51.064414 -271.266666)
		(size 0.4572)
		(drill 0.2032)
		(layers "F.Cu" "B.Cu")
		(net "GND")
	)
	(via
		(at 352.406204 -332.56601)
		(size 0.49022)
		(drill 0.254)
		(layers "F.Cu" "B.Cu")
		(net "GND")
	)
	(via
		(at 264.729214 -304.416714)
		(size 0.4572)
		(drill 0.2032)
		(layers "F.Cu" "B.Cu")
		(net "GND")
	)
	(via
		(at 244.018562 -54.017672)
		(size 0.508)
		(drill 0.254)
		(layers "F.Cu" "B.Cu")
		(net "GND")
	)
	(via
		(at 412.990792 -360.026712)
		(size 0.508)
		(drill 0.254)
		(layers "F.Cu" "B.Cu")
		(net "GND")
	)
	(via
		(at 257.185414 -250.016772)
		(size 0.4572)
		(drill 0.2032)
		(layers "F.Cu" "B.Cu")
		(net "GND")
	)
	(via
		(at 142.94612 -8.341868)
		(size 0.508)
		(drill 0.254)
		(layers "F.Cu" "B.Cu")
		(net "GND")
	)
	(via
		(at 27.315668 -4.962652)
		(size 0.508)
		(drill 0.254)
		(layers "F.Cu" "B.Cu")
		(net "GND")
	)
	(via
		(at 427.290484 -360.148378)
		(size 0.49022)
		(drill 0.254)
		(layers "F.Cu" "B.Cu")
		(net "GND")
	)
	(via
		(at 373.677434 -229.272846)
		(size 0.4572)
		(drill 0.2032)
		(layers "F.Cu" "B.Cu")
		(net "GND")
	)
	(via
		(at 455.011282 -277.216616)
		(size 0.4572)
		(drill 0.2032)
		(layers "F.Cu" "B.Cu")
		(net "GND")
	)
	(via
		(at 194.193414 -219.41663)
		(size 0.4572)
		(drill 0.2032)
		(layers "F.Cu" "B.Cu")
		(net "GND")
	)
	(via
		(at 393.896596 -19.759422)
		(size 0.508)
		(drill 0.254)
		(layers "F.Cu" "B.Cu")
		(net "GND")
	)
	(via
		(at 89.664794 -267.755878)
		(size 0.4572)
		(drill 0.2032)
		(layers "F.Cu" "B.Cu")
		(net "GND")
	)
	(via
		(at 179.105814 -299.316648)
		(size 0.4572)
		(drill 0.2032)
		(layers "F.Cu" "B.Cu")
		(net "GND")
	)
	(via
		(at 370.858034 -216.25052)
		(size 0.4572)
		(drill 0.2032)
		(layers "F.Cu" "B.Cu")
		(net "GND")
	)
	(via
		(at 343.13368 -230.086662)
		(size 0.4572)
		(drill 0.2032)
		(layers "F.Cu" "B.Cu")
		(net "GND")
	)
	(via
		(at 127.726948 -275.08073)
		(size 0.4572)
		(drill 0.2032)
		(layers "F.Cu" "B.Cu")
		(net "GND")
	)
	(via
		(at 243.854986 -98.299016)
		(size 0.508)
		(drill 0.254)
		(layers "F.Cu" "B.Cu")
		(net "GND")
	)
	(via
		(at 33.767014 -282.316682)
		(size 0.4572)
		(drill 0.2032)
		(layers "F.Cu" "B.Cu")
		(net "GND")
	)
	(via
		(at 13.345414 -262.76681)
		(size 0.4572)
		(drill 0.2032)
		(layers "F.Cu" "B.Cu")
		(net "GND")
	)
	(via
		(at 390.844278 -344.51417)
		(size 0.508)
		(drill 0.254)
		(layers "F.Cu" "B.Cu")
		(net "GND")
	)
	(via
		(at 335.761076 -410.664152)
		(size 0.4572)
		(drill 0.254)
		(layers "F.Cu" "B.Cu")
		(net "GND")
	)
	(via
		(at 348.465648 -329.119738)
		(size 0.508)
		(drill 0.254)
		(layers "F.Cu" "B.Cu")
		(net "GND")
	)
	(via
		(at 254.635 -68.544948)
		(size 0.508)
		(drill 0.254)
		(layers "F.Cu" "B.Cu")
		(net "GND")
	)
	(via
		(at 302.448214 -315.46673)
		(size 0.4572)
		(drill 0.2032)
		(layers "F.Cu" "B.Cu")
		(net "GND")
	)
	(via
		(at 335.140808 -42.341546)
		(size 0.4572)
		(drill 0.2032)
		(layers "F.Cu" "B.Cu")
		(net "GND")
	)
	(via
		(at 447.449448 -180.910992)
		(size 0.508)
		(drill 0.254)
		(layers "F.Cu" "B.Cu")
		(net "GND")
	)
	(via
		(at 428.279814 -295.06672)
		(size 0.4572)
		(drill 0.2032)
		(layers "F.Cu" "B.Cu")
		(net "GND")
	)
	(via
		(at 314.23102 -404.51786)
		(size 0.4572)
		(drill 0.254)
		(layers "F.Cu" "B.Cu")
		(net "GND")
	)
	(via
		(at 66.152014 -288.266632)
		(size 0.4572)
		(drill 0.2032)
		(layers "F.Cu" "B.Cu")
		(net "GND")
	)
	(via
		(at 212.724746 -197.316598)
		(size 0.4572)
		(drill 0.2032)
		(layers "F.Cu" "B.Cu")
		(net "GND")
	)
	(via
		(at 414.01365 -407.00452)
		(size 0.4064)
		(drill 0.2032)
		(layers "F.Cu" "B.Cu")
		(net "GND")
	)
	(via
		(at 415.402014 -306.116736)
		(size 0.4572)
		(drill 0.2032)
		(layers "F.Cu" "B.Cu")
		(net "GND")
	)
	(via
		(at 325.95312 -348.564454)
		(size 0.508)
		(drill 0.254)
		(layers "F.Cu" "B.Cu")
		(net "GND")
	)
	(via
		(at 18.679414 -241.516662)
		(size 0.4572)
		(drill 0.2032)
		(layers "F.Cu" "B.Cu")
		(net "GND")
	)
	(via
		(at 131.752086 -406.370536)
		(size 0.4572)
		(drill 0.254)
		(layers "F.Cu" "B.Cu")
		(net "GND")
	)
	(via
		(at 305.318922 -323.373242)
		(size 0.4572)
		(drill 0.2032)
		(layers "F.Cu" "B.Cu")
		(net "GND")
	)
	(via
		(at 304.338482 -305.266598)
		(size 0.4572)
		(drill 0.2032)
		(layers "F.Cu" "B.Cu")
		(net "GND")
	)
	(via
		(at 102.866444 -259.696458)
		(size 0.4572)
		(drill 0.2032)
		(layers "F.Cu" "B.Cu")
		(net "GND")
	)
	(via
		(at 372.737634 -222.761556)
		(size 0.4572)
		(drill 0.2032)
		(layers "F.Cu" "B.Cu")
		(net "GND")
	)
	(via
		(at 136.544812 -236.597952)
		(size 0.4318)
		(drill 0.2032)
		(layers "F.Cu" "B.Cu")
		(net "GND")
	)
	(via
		(at 191.983614 -266.1666)
		(size 0.4572)
		(drill 0.2032)
		(layers "F.Cu" "B.Cu")
		(net "GND")
	)
	(via
		(at 130.807206 -330.227432)
		(size 0.508)
		(drill 0.254)
		(layers "F.Cu" "B.Cu")
		(net "GND")
	)
	(via
		(at 214.615014 -295.916604)
		(size 0.4572)
		(drill 0.2032)
		(layers "F.Cu" "B.Cu")
		(net "GND")
	)
	(via
		(at 425.71416 -144.685258)
		(size 0.508)
		(drill 0.254)
		(layers "F.Cu" "B.Cu")
		(net "GND")
	)
	(via
		(at 119.268494 -289.807142)
		(size 0.4572)
		(drill 0.2032)
		(layers "F.Cu" "B.Cu")
		(net "GND")
	)
	(via
		(at 169.352214 -288.266632)
		(size 0.4572)
		(drill 0.2032)
		(layers "F.Cu" "B.Cu")
		(net "GND")
	)
	(via
		(at 447.16065 -7.20344)
		(size 0.508)
		(drill 0.254)
		(layers "F.Cu" "B.Cu")
		(net "GND")
	)
	(via
		(at 86.250018 -436.051198)
		(size 0.4572)
		(drill 0.2032)
		(layers "F.Cu" "B.Cu")
		(net "GND")
	)
	(via
		(at 302.448214 -201.56678)
		(size 0.4572)
		(drill 0.2032)
		(layers "F.Cu" "B.Cu")
		(net "GND")
	)
	(via
		(at 460.664814 -236.416596)
		(size 0.4572)
		(drill 0.2032)
		(layers "F.Cu" "B.Cu")
		(net "GND")
	)
	(via
		(at 380.725934 -238.225584)
		(size 0.4572)
		(drill 0.2032)
		(layers "F.Cu" "B.Cu")
		(net "GND")
	)
	(via
		(at 94.363794 -261.244842)
		(size 0.4572)
		(drill 0.2032)
		(layers "F.Cu" "B.Cu")
		(net "GND")
	)
	(via
		(at 96.133412 -234.970066)
		(size 0.4572)
		(drill 0.2032)
		(layers "F.Cu" "B.Cu")
		(net "GND")
	)
	(via
		(at 140.598144 -78.111858)
		(size 0.508)
		(drill 0.254)
		(layers "F.Cu" "B.Cu")
		(net "GND")
	)
	(via
		(at 103.8098 -407.289)
		(size 0.508)
		(drill 0.254)
		(layers "F.Cu" "B.Cu")
		(net "GND")
	)
	(via
		(at 344.25001 -437.49976)
		(size 0.4572)
		(drill 0.2032)
		(layers "F.Cu" "B.Cu")
		(net "GND")
	)
	(via
		(at 67.42049 -404.51786)
		(size 0.4572)
		(drill 0.254)
		(layers "F.Cu" "B.Cu")
		(net "GND")
	)
	(via
		(at 289.250882 -299.316648)
		(size 0.4572)
		(drill 0.2032)
		(layers "F.Cu" "B.Cu")
		(net "GND")
	)
	(via
		(at 453.121014 -258.516628)
		(size 0.4572)
		(drill 0.2032)
		(layers "F.Cu" "B.Cu")
		(net "GND")
	)
	(via
		(at 335.615534 -246.364506)
		(size 0.4572)
		(drill 0.2032)
		(layers "F.Cu" "B.Cu")
		(net "GND")
	)
	(via
		(at 358.280462 -269.38351)
		(size 0.4572)
		(drill 0.2032)
		(layers "F.Cu" "B.Cu")
		(net "GND")
	)
	(via
		(at 102.509574 -95.47352)
		(size 0.508)
		(drill 0.254)
		(layers "F.Cu" "B.Cu")
		(net "GND")
	)
	(via
		(at 26.223214 -316.316614)
		(size 0.4572)
		(drill 0.2032)
		(layers "F.Cu" "B.Cu")
		(net "GND")
	)
	(via
		(at 387.818122 -247.042432)
		(size 0.4572)
		(drill 0.2032)
		(layers "F.Cu" "B.Cu")
		(net "GND")
	)
	(via
		(at 31.876746 -295.06672)
		(size 0.4572)
		(drill 0.2032)
		(layers "F.Cu" "B.Cu")
		(net "GND")
	)
	(via
		(at 372.26748 -246.364506)
		(size 0.4572)
		(drill 0.2032)
		(layers "F.Cu" "B.Cu")
		(net "GND")
	)
	(via
		(at 409.985464 -358.436926)
		(size 0.508)
		(drill 0.254)
		(layers "F.Cu" "B.Cu")
		(net "GND")
	)
	(via
		(at 94.364048 -275.8948)
		(size 0.4572)
		(drill 0.2032)
		(layers "F.Cu" "B.Cu")
		(net "GND")
	)
	(via
		(at 106.471466 -217.064336)
		(size 0.4572)
		(drill 0.2032)
		(layers "F.Cu" "B.Cu")
		(net "GND")
	)
	(via
		(at 30.248098 -139.066524)
		(size 0.508)
		(drill 0.254)
		(layers "F.Cu" "B.Cu")
		(net "GND")
	)
	(via
		(at 175.005746 -296.766742)
		(size 0.4572)
		(drill 0.2032)
		(layers "F.Cu" "B.Cu")
		(net "GND")
	)
	(via
		(at 458.455014 -295.06672)
		(size 0.4572)
		(drill 0.2032)
		(layers "F.Cu" "B.Cu")
		(net "GND")
	)
	(via
		(at 88.255094 -281.59202)
		(size 0.4572)
		(drill 0.2032)
		(layers "F.Cu" "B.Cu")
		(net "GND")
	)
	(via
		(at 187.883546 -233.016806)
		(size 0.4572)
		(drill 0.2032)
		(layers "F.Cu" "B.Cu")
		(net "GND")
	)
	(via
		(at 257.185414 -270.416782)
		(size 0.4572)
		(drill 0.2032)
		(layers "F.Cu" "B.Cu")
		(net "GND")
	)
	(via
		(at 425.868084 -361.726734)
		(size 0.49022)
		(drill 0.254)
		(layers "F.Cu" "B.Cu")
		(net "GND")
	)
	(via
		(at 126.207012 -246.364506)
		(size 0.4572)
		(drill 0.2032)
		(layers "F.Cu" "B.Cu")
		(net "GND")
	)
	(via
		(at 223.248474 -129.298954)
		(size 0.508)
		(drill 0.254)
		(layers "F.Cu" "B.Cu")
		(net "GND")
	)
	(via
		(at 334.325468 -40.931846)
		(size 0.4572)
		(drill 0.2032)
		(layers "F.Cu" "B.Cu")
		(net "GND")
	)
	(via
		(at 66.152014 -314.616592)
		(size 0.4572)
		(drill 0.2032)
		(layers "F.Cu" "B.Cu")
		(net "GND")
	)
	(via
		(at 422.945814 -195.616576)
		(size 0.4572)
		(drill 0.2032)
		(layers "F.Cu" "B.Cu")
		(net "GND")
	)
	(via
		(at 311.666382 -284.866588)
		(size 0.4572)
		(drill 0.2032)
		(layers "F.Cu" "B.Cu")
		(net "GND")
	)
	(via
		(at 244.80012 -253.363984)
		(size 0.508)
		(drill 0.254)
		(layers "F.Cu" "B.Cu")
		(net "GND")
	)
	(via
		(at 62.051946 -278.066754)
		(size 0.4572)
		(drill 0.2032)
		(layers "F.Cu" "B.Cu")
		(net "GND")
	)
	(via
		(at 467.535514 -134.48538)
		(size 0.508)
		(drill 0.254)
		(layers "F.Cu" "B.Cu")
		(net "GND")
	)
	(via
		(at 268.068552 -323.429376)
		(size 0.4572)
		(drill 0.2032)
		(layers "F.Cu" "B.Cu")
		(net "GND")
	)
	(via
		(at 65.70345 -410.664152)
		(size 0.4572)
		(drill 0.254)
		(layers "F.Cu" "B.Cu")
		(net "GND")
	)
	(via
		(at 450.911214 -315.46673)
		(size 0.4572)
		(drill 0.2032)
		(layers "F.Cu" "B.Cu")
		(net "GND")
	)
	(via
		(at 309.992014 -295.06672)
		(size 0.4572)
		(drill 0.2032)
		(layers "F.Cu" "B.Cu")
		(net "GND")
	)
	(via
		(at 318.737488 -403.883876)
		(size 0.4064)
		(drill 0.2032)
		(layers "F.Cu" "B.Cu")
		(net "GND")
	)
	(via
		(at 62.92088 -18.252948)
		(size 0.508)
		(drill 0.254)
		(layers "F.Cu" "B.Cu")
		(net "GND")
	)
	(via
		(at 187.883546 -195.616576)
		(size 0.4572)
		(drill 0.2032)
		(layers "F.Cu" "B.Cu")
		(net "GND")
	)
	(via
		(at 136.185148 -275.080984)
		(size 0.4318)
		(drill 0.2032)
		(layers "F.Cu" "B.Cu")
		(net "GND")
	)
	(via
		(at 41.310814 -301.01667)
		(size 0.4572)
		(drill 0.2032)
		(layers "F.Cu" "B.Cu")
		(net "GND")
	)
	(via
		(at 438.033414 -206.666592)
		(size 0.4572)
		(drill 0.2032)
		(layers "F.Cu" "B.Cu")
		(net "GND")
	)
	(via
		(at 179.105814 -211.766658)
		(size 0.4572)
		(drill 0.2032)
		(layers "F.Cu" "B.Cu")
		(net "GND")
	)
	(via
		(at 26.223214 -224.516696)
		(size 0.4572)
		(drill 0.2032)
		(layers "F.Cu" "B.Cu")
		(net "GND")
	)
	(via
		(at 356.634034 -50.207672)
		(size 0.49022)
		(drill 0.254)
		(layers "F.Cu" "B.Cu")
		(net "GND")
	)
	(via
		(at 237.615984 -56.965088)
		(size 0.508)
		(drill 0.254)
		(layers "F.Cu" "B.Cu")
		(net "GND")
	)
	(via
		(at 460.664814 -260.21665)
		(size 0.4572)
		(drill 0.2032)
		(layers "F.Cu" "B.Cu")
		(net "GND")
	)
	(via
		(at 378.486162 -283.219906)
		(size 0.4572)
		(drill 0.2032)
		(layers "F.Cu" "B.Cu")
		(net "GND")
	)
	(via
		(at 427.764448 -18.491454)
		(size 0.508)
		(drill 0.254)
		(layers "F.Cu" "B.Cu")
		(net "GND")
	)
	(via
		(at 340.784434 -237.411514)
		(size 0.4572)
		(drill 0.2032)
		(layers "F.Cu" "B.Cu")
		(net "GND")
	)
	(via
		(at 131.550156 -10.733278)
		(size 0.508)
		(drill 0.254)
		(layers "F.Cu" "B.Cu")
		(net "GND")
	)
	(via
		(at 125.986794 -410.030168)
		(size 0.4064)
		(drill 0.2032)
		(layers "F.Cu" "B.Cu")
		(net "GND")
	)
	(via
		(at 431.656998 -363.54893)
		(size 0.508)
		(drill 0.254)
		(layers "F.Cu" "B.Cu")
		(net "GND")
	)
	(via
		(at 443.367414 -201.56678)
		(size 0.4572)
		(drill 0.2032)
		(layers "F.Cu" "B.Cu")
		(net "GND")
	)
	(via
		(at 388.52094 -53.749956)
		(size 0.508)
		(drill 0.254)
		(layers "F.Cu" "B.Cu")
		(net "GND")
	)
	(via
		(at 205.180946 -313.766708)
		(size 0.4572)
		(drill 0.2032)
		(layers "F.Cu" "B.Cu")
		(net "GND")
	)
	(via
		(at 197.637146 -261.916672)
		(size 0.4572)
		(drill 0.2032)
		(layers "F.Cu" "B.Cu")
		(net "GND")
	)
	(via
		(at 308.191916 -406.370536)
		(size 0.4572)
		(drill 0.254)
		(layers "F.Cu" "B.Cu")
		(net "GND")
	)
	(via
		(at 439.923682 -247.466612)
		(size 0.4572)
		(drill 0.2032)
		(layers "F.Cu" "B.Cu")
		(net "GND")
	)
	(via
		(at 132.315966 -248.806208)
		(size 0.4572)
		(drill 0.2032)
		(layers "F.Cu" "B.Cu")
		(net "GND")
	)
	(via
		(at 134.259066 -341.564722)
		(size 0.508)
		(drill 0.254)
		(layers "F.Cu" "B.Cu")
		(net "GND")
	)
	(via
		(at 407.34996 -433.899564)
		(size 0.4572)
		(drill 0.2032)
		(layers "F.Cu" "B.Cu")
		(net "GND")
	)
	(via
		(at 276.373082 -222.816674)
		(size 0.4572)
		(drill 0.2032)
		(layers "F.Cu" "B.Cu")
		(net "GND")
	)
	(via
		(at 372.947184 -330.42352)
		(size 0.508)
		(drill 0.254)
		(layers "F.Cu" "B.Cu")
		(net "GND")
	)
	(via
		(at 22.123146 -267.016738)
		(size 0.4572)
		(drill 0.2032)
		(layers "F.Cu" "B.Cu")
		(net "GND")
	)
	(via
		(at 145.809462 -407.638504)
		(size 0.4572)
		(drill 0.254)
		(layers "F.Cu" "B.Cu")
		(net "GND")
	)
	(via
		(at 390.349994 -425.547282)
		(size 0.4572)
		(drill 0.2032)
		(layers "F.Cu" "B.Cu")
		(net "GND")
	)
	(via
		(at 78.250034 -427.699678)
		(size 0.4572)
		(drill 0.2032)
		(layers "F.Cu" "B.Cu")
		(net "GND")
	)
	(via
		(at 433.352448 -19.759422)
		(size 0.508)
		(drill 0.254)
		(layers "F.Cu" "B.Cu")
		(net "GND")
	)
	(via
		(at 432.379882 -202.416664)
		(size 0.4572)
		(drill 0.2032)
		(layers "F.Cu" "B.Cu")
		(net "GND")
	)
	(via
		(at 41.310814 -241.516662)
		(size 0.4572)
		(drill 0.2032)
		(layers "F.Cu" "B.Cu")
		(net "GND")
	)
	(via
		(at 173.467014 -17.775428)
		(size 0.508)
		(drill 0.254)
		(layers "F.Cu" "B.Cu")
		(net "GND")
	)
	(via
		(at 68.863718 -403.883876)
		(size 0.4064)
		(drill 0.2032)
		(layers "F.Cu" "B.Cu")
		(net "GND")
	)
	(via
		(at 259.075682 -289.966654)
		(size 0.4572)
		(drill 0.2032)
		(layers "F.Cu" "B.Cu")
		(net "GND")
	)
	(via
		(at 194.193414 -282.316682)
		(size 0.4572)
		(drill 0.2032)
		(layers "F.Cu" "B.Cu")
		(net "GND")
	)
	(via
		(at 285.150814 -236.416596)
		(size 0.4572)
		(drill 0.2032)
		(layers "F.Cu" "B.Cu")
		(net "GND")
	)
	(via
		(at 51.198018 -6.090412)
		(size 0.508)
		(drill 0.254)
		(layers "F.Cu" "B.Cu")
		(net "GND")
	)
	(via
		(at 24.332946 -204.96657)
		(size 0.4572)
		(drill 0.2032)
		(layers "F.Cu" "B.Cu")
		(net "GND")
	)
	(via
		(at 158.2801 -69.385688)
		(size 0.508)
		(drill 0.254)
		(layers "F.Cu" "B.Cu")
		(net "GND")
	)
	(via
		(at 307.566314 -311.216802)
		(size 0.4572)
		(drill 0.2032)
		(layers "F.Cu" "B.Cu")
		(net "GND")
	)
	(via
		(at 252.020832 -439.905394)
		(size 0.508)
		(drill 0.254)
		(layers "F.Cu" "B.Cu")
		(net "GND")
	)
	(via
		(at 90.964766 -243.922804)
		(size 0.4572)
		(drill 0.2032)
		(layers "F.Cu" "B.Cu")
		(net "GND")
	)
	(via
		(at 422.945814 -287.416748)
		(size 0.4572)
		(drill 0.2032)
		(layers "F.Cu" "B.Cu")
		(net "GND")
	)
	(via
		(at 63.250064 -430.299622)
		(size 0.4572)
		(drill 0.2032)
		(layers "F.Cu" "B.Cu")
		(net "GND")
	)
	(via
		(at 306.548282 -228.766624)
		(size 0.4572)
		(drill 0.2032)
		(layers "F.Cu" "B.Cu")
		(net "GND")
	)
	(via
		(at 334.926686 -12.544552)
		(size 0.508)
		(drill 0.254)
		(layers "F.Cu" "B.Cu")
		(net "GND")
	)
	(via
		(at 123.66879 -332.570074)
		(size 0.49022)
		(drill 0.254)
		(layers "F.Cu" "B.Cu")
		(net "GND")
	)
	(via
		(at 444.268352 -332.860396)
		(size 0.4572)
		(drill 0.2032)
		(layers "F.Cu" "B.Cu")
		(net "GND")
	)
	(via
		(at 58.688986 -221.255336)
		(size 0.4572)
		(drill 0.2032)
		(layers "F.Cu" "B.Cu")
		(net "GND")
	)
	(via
		(at 94.363794 -259.616956)
		(size 0.4572)
		(drill 0.2032)
		(layers "F.Cu" "B.Cu")
		(net "GND")
	)
	(via
		(at 92.013786 -406.34666)
		(size 0.4572)
		(drill 0.254)
		(layers "F.Cu" "B.Cu")
		(net "GND")
	)
	(via
		(at 344.073734 -247.992138)
		(size 0.4572)
		(drill 0.2032)
		(layers "F.Cu" "B.Cu")
		(net "GND")
	)
	(via
		(at 54.78145 -350.255332)
		(size 0.508)
		(drill 0.254)
		(layers "F.Cu" "B.Cu")
		(net "GND")
	)
	(via
		(at 344.86342 -401.492212)
		(size 0.4572)
		(drill 0.254)
		(layers "F.Cu" "B.Cu")
		(net "GND")
	)
	(via
		(at 72.191118 -407.00452)
		(size 0.4064)
		(drill 0.2032)
		(layers "F.Cu" "B.Cu")
		(net "GND")
	)
	(via
		(at 420.989252 -365.291624)
		(size 0.508)
		(drill 0.254)
		(layers "F.Cu" "B.Cu")
		(net "GND")
	)
	(via
		(at 445.593978 -67.592194)
		(size 0.508)
		(drill 0.254)
		(layers "F.Cu" "B.Cu")
		(net "GND")
	)
	(via
		(at 199.527414 -291.666676)
		(size 0.4572)
		(drill 0.2032)
		(layers "F.Cu" "B.Cu")
		(net "GND")
	)
	(via
		(at 132.785612 -246.364506)
		(size 0.4572)
		(drill 0.2032)
		(layers "F.Cu" "B.Cu")
		(net "GND")
	)
	(via
		(at 210.514946 -295.06672)
		(size 0.4572)
		(drill 0.2032)
		(layers "F.Cu" "B.Cu")
		(net "GND")
	)
	(via
		(at 464.764882 -194.766692)
		(size 0.4572)
		(drill 0.2032)
		(layers "F.Cu" "B.Cu")
		(net "GND")
	)
	(via
		(at 61.020198 -410.030168)
		(size 0.4064)
		(drill 0.2032)
		(layers "F.Cu" "B.Cu")
		(net "GND")
	)
	(via
		(at 71.250048 -436.347362)
		(size 0.4572)
		(drill 0.2032)
		(layers "F.Cu" "B.Cu")
		(net "GND")
	)
	(via
		(at 449.677282 -250.866656)
		(size 0.4572)
		(drill 0.2032)
		(layers "F.Cu" "B.Cu")
		(net "GND")
	)
	(via
		(at 20.889214 -221.116652)
		(size 0.4572)
		(drill 0.2032)
		(layers "F.Cu" "B.Cu")
		(net "GND")
	)
	(via
		(at 126.207266 -243.108988)
		(size 0.4572)
		(drill 0.2032)
		(layers "F.Cu" "B.Cu")
		(net "GND")
	)
	(via
		(at 52.298346 -296.766742)
		(size 0.4572)
		(drill 0.2032)
		(layers "F.Cu" "B.Cu")
		(net "GND")
	)
	(via
		(at 169.352214 -299.316648)
		(size 0.4572)
		(drill 0.2032)
		(layers "F.Cu" "B.Cu")
		(net "GND")
	)
	(via
		(at 453.121014 -195.616576)
		(size 0.4572)
		(drill 0.2032)
		(layers "F.Cu" "B.Cu")
		(net "GND")
	)
	(via
		(at 37.210746 -229.616762)
		(size 0.4572)
		(drill 0.2032)
		(layers "F.Cu" "B.Cu")
		(net "GND")
	)
	(via
		(at 132.895594 -259.616956)
		(size 0.4572)
		(drill 0.2032)
		(layers "F.Cu" "B.Cu")
		(net "GND")
	)
	(via
		(at 375.557034 -232.528364)
		(size 0.4572)
		(drill 0.2032)
		(layers "F.Cu" "B.Cu")
		(net "GND")
	)
	(via
		(at 16.789146 -261.916672)
		(size 0.4572)
		(drill 0.2032)
		(layers "F.Cu" "B.Cu")
		(net "GND")
	)
	(via
		(at 94.833694 -263.686544)
		(size 0.4572)
		(drill 0.2032)
		(layers "F.Cu" "B.Cu")
		(net "GND")
	)
	(via
		(at 54.724046 -208.366614)
		(size 0.4572)
		(drill 0.2032)
		(layers "F.Cu" "B.Cu")
		(net "GND")
	)
	(via
		(at 46.964346 -260.21665)
		(size 0.4572)
		(drill 0.2032)
		(layers "F.Cu" "B.Cu")
		(net "GND")
	)
	(via
		(at 402.331174 -5.585714)
		(size 0.508)
		(drill 0.254)
		(layers "F.Cu" "B.Cu")
		(net "GND")
	)
	(via
		(at 187.883546 -272.116804)
		(size 0.4572)
		(drill 0.2032)
		(layers "F.Cu" "B.Cu")
		(net "GND")
	)
	(via
		(at 348.302834 -219.506038)
		(size 0.4572)
		(drill 0.2032)
		(layers "F.Cu" "B.Cu")
		(net "GND")
	)
	(via
		(at 33.767014 -194.766692)
		(size 0.4572)
		(drill 0.2032)
		(layers "F.Cu" "B.Cu")
		(net "GND")
	)
	(via
		(at 336.085434 -226.017328)
		(size 0.4572)
		(drill 0.2032)
		(layers "F.Cu" "B.Cu")
		(net "GND")
	)
	(via
		(at 9.245346 -233.016806)
		(size 0.4572)
		(drill 0.2032)
		(layers "F.Cu" "B.Cu")
		(net "GND")
	)
	(via
		(at 279.816814 -199.01662)
		(size 0.4572)
		(drill 0.2032)
		(layers "F.Cu" "B.Cu")
		(net "GND")
	)
	(via
		(at 384.350006 -432.451256)
		(size 0.4572)
		(drill 0.2032)
		(layers "F.Cu" "B.Cu")
		(net "GND")
	)
	(via
		(at 101.381306 -326.823832)
		(size 0.508)
		(drill 0.254)
		(layers "F.Cu" "B.Cu")
		(net "GND")
	)
	(via
		(at 420.736014 -217.716608)
		(size 0.4572)
		(drill 0.2032)
		(layers "F.Cu" "B.Cu")
		(net "GND")
	)
	(via
		(at 123.065286 -326.859392)
		(size 0.508)
		(drill 0.254)
		(layers "F.Cu" "B.Cu")
		(net "GND")
	)
	(via
		(at 115.423442 -241.081306)
		(size 0.4572)
		(drill 0.2032)
		(layers "F.Cu" "B.Cu")
		(net "GND")
	)
	(via
		(at 41.310814 -275.516594)
		(size 0.4572)
		(drill 0.2032)
		(layers "F.Cu" "B.Cu")
		(net "GND")
	)
	(via
		(at 42.057066 -9.424924)
		(size 0.508)
		(drill 0.254)
		(layers "F.Cu" "B.Cu")
		(net "GND")
	)
	(via
		(at 453.183752 -319.446656)
		(size 0.4572)
		(drill 0.2032)
		(layers "F.Cu" "B.Cu")
		(net "GND")
	)
	(via
		(at 31.876746 -233.016806)
		(size 0.4572)
		(drill 0.2032)
		(layers "F.Cu" "B.Cu")
		(net "GND")
	)
	(via
		(at 264.729214 -258.516628)
		(size 0.4572)
		(drill 0.2032)
		(layers "F.Cu" "B.Cu")
		(net "GND")
	)
	(via
		(at 302.664114 -210.916774)
		(size 0.4572)
		(drill 0.2032)
		(layers "F.Cu" "B.Cu")
		(net "GND")
	)
	(via
		(at 189.861698 -12.461748)
		(size 0.508)
		(drill 0.254)
		(layers "F.Cu" "B.Cu")
		(net "GND")
	)
	(via
		(at 294.904414 -276.366732)
		(size 0.4572)
		(drill 0.2032)
		(layers "F.Cu" "B.Cu")
		(net "GND")
	)
	(via
		(at 408.11069 -206.666592)
		(size 0.4572)
		(drill 0.2032)
		(layers "F.Cu" "B.Cu")
		(net "GND")
	)
	(via
		(at 259.075682 -238.116618)
		(size 0.4572)
		(drill 0.2032)
		(layers "F.Cu" "B.Cu")
		(net "GND")
	)
	(via
		(at 131.849114 -403.883876)
		(size 0.4064)
		(drill 0.2032)
		(layers "F.Cu" "B.Cu")
		(net "GND")
	)
	(via
		(at 398.225772 -19.759422)
		(size 0.508)
		(drill 0.254)
		(layers "F.Cu" "B.Cu")
		(net "GND")
	)
	(via
		(at 207.071214 -211.766658)
		(size 0.4572)
		(drill 0.2032)
		(layers "F.Cu" "B.Cu")
		(net "GND")
	)
	(via
		(at 326.571356 -407.638504)
		(size 0.4572)
		(drill 0.254)
		(layers "F.Cu" "B.Cu")
		(net "GND")
	)
	(via
		(at 127.627126 -335.976214)
		(size 0.49022)
		(drill 0.254)
		(layers "F.Cu" "B.Cu")
		(net "GND")
	)
	(via
		(at 62.267846 -313.766708)
		(size 0.4572)
		(drill 0.2032)
		(layers "F.Cu" "B.Cu")
		(net "GND")
	)
	(via
		(at 22.24151 -170.292014)
		(size 0.508)
		(drill 0.254)
		(layers "F.Cu" "B.Cu")
		(net "GND")
	)
	(via
		(at 62.051946 -281.466798)
		(size 0.4572)
		(drill 0.2032)
		(layers "F.Cu" "B.Cu")
		(net "GND")
	)
	(via
		(at 71.82993 -407.638504)
		(size 0.4572)
		(drill 0.254)
		(layers "F.Cu" "B.Cu")
		(net "GND")
	)
	(via
		(at 398.446752 -9.424924)
		(size 0.508)
		(drill 0.254)
		(layers "F.Cu" "B.Cu")
		(net "GND")
	)
	(via
		(at 143.34998 -429.147224)
		(size 0.4572)
		(drill 0.2032)
		(layers "F.Cu" "B.Cu")
		(net "GND")
	)
	(via
		(at 372.26748 -247.992138)
		(size 0.4572)
		(drill 0.2032)
		(layers "F.Cu" "B.Cu")
		(net "GND")
	)
	(via
		(at 2.764536 -102.030022)
		(size 0.508)
		(drill 0.254)
		(layers "F.Cu" "B.Cu")
		(net "GND")
	)
	(via
		(at 428.279814 -246.616728)
		(size 0.4572)
		(drill 0.2032)
		(layers "F.Cu" "B.Cu")
		(net "GND")
	)
	(via
		(at 62.051946 -263.616694)
		(size 0.4572)
		(drill 0.2032)
		(layers "F.Cu" "B.Cu")
		(net "GND")
	)
	(via
		(at 464.764882 -272.966688)
		(size 0.4572)
		(drill 0.2032)
		(layers "F.Cu" "B.Cu")
		(net "GND")
	)
	(via
		(at 181.407308 -51.14671)
		(size 0.508)
		(drill 0.254)
		(layers "F.Cu" "B.Cu")
		(net "GND")
	)
	(via
		(at 11.135614 -211.766658)
		(size 0.4572)
		(drill 0.2032)
		(layers "F.Cu" "B.Cu")
		(net "GND")
	)
	(via
		(at 336.195162 -263.686544)
		(size 0.4572)
		(drill 0.2032)
		(layers "F.Cu" "B.Cu")
		(net "GND")
	)
	(via
		(at 18.679414 -312.91657)
		(size 0.4572)
		(drill 0.2032)
		(layers "F.Cu" "B.Cu")
		(net "GND")
	)
	(via
		(at 395.273022 -410.664152)
		(size 0.4572)
		(drill 0.254)
		(layers "F.Cu" "B.Cu")
		(net "GND")
	)
	(via
		(at 366.372902 -254.014986)
		(size 0.4572)
		(drill 0.2032)
		(layers "F.Cu" "B.Cu")
		(net "GND")
	)
	(via
		(at 150.684992 -40.50792)
		(size 0.508)
		(drill 0.254)
		(layers "F.Cu" "B.Cu")
		(net "GND")
	)
	(via
		(at 378.486416 -281.59202)
		(size 0.4572)
		(drill 0.2032)
		(layers "F.Cu" "B.Cu")
		(net "GND")
	)
	(via
		(at 41.310814 -245.76659)
		(size 0.4572)
		(drill 0.2032)
		(layers "F.Cu" "B.Cu")
		(net "GND")
	)
	(via
		(at 39.420546 -309.51678)
		(size 0.4572)
		(drill 0.2032)
		(layers "F.Cu" "B.Cu")
		(net "GND")
	)
	(via
		(at 73.273158 -410.030168)
		(size 0.4064)
		(drill 0.2032)
		(layers "F.Cu" "B.Cu")
		(net "GND")
	)
	(via
		(at 272.36674 -92.563188)
		(size 0.508)
		(drill 0.254)
		(layers "F.Cu" "B.Cu")
		(net "GND")
	)
	(via
		(at 311.16778 -400.224244)
		(size 0.4572)
		(drill 0.254)
		(layers "F.Cu" "B.Cu")
		(net "GND")
	)
	(via
		(at 187.883546 -268.71676)
		(size 0.4572)
		(drill 0.2032)
		(layers "F.Cu" "B.Cu")
		(net "GND")
	)
	(via
		(at 284.778196 -359.393744)
		(size 0.508)
		(drill 0.254)
		(layers "F.Cu" "B.Cu")
		(net "GND")
	)
	(via
		(at 373.787416 -273.453098)
		(size 0.4572)
		(drill 0.2032)
		(layers "F.Cu" "B.Cu")
		(net "GND")
	)
	(via
		(at 432.379882 -314.616592)
		(size 0.4572)
		(drill 0.2032)
		(layers "F.Cu" "B.Cu")
		(net "GND")
	)
	(via
		(at 377.546362 -253.919736)
		(size 0.4572)
		(drill 0.2032)
		(layers "F.Cu" "B.Cu")
		(net "GND")
	)
	(via
		(at 418.60343 -6.586474)
		(size 0.508)
		(drill 0.254)
		(layers "F.Cu" "B.Cu")
		(net "GND")
	)
	(via
		(at 384.485134 -226.831144)
		(size 0.4318)
		(drill 0.2032)
		(layers "F.Cu" "B.Cu")
		(net "GND")
	)
	(via
		(at 22.18309 -16.978376)
		(size 0.508)
		(drill 0.254)
		(layers "F.Cu" "B.Cu")
		(net "GND")
	)
	(via
		(at 133.868668 -128.48082)
		(size 0.508)
		(drill 0.254)
		(layers "F.Cu" "B.Cu")
		(net "GND")
	)
	(via
		(at 93.314012 -244.73662)
		(size 0.4572)
		(drill 0.2032)
		(layers "F.Cu" "B.Cu")
		(net "GND")
	)
	(via
		(at 268.829282 -250.866656)
		(size 0.4572)
		(drill 0.2032)
		(layers "F.Cu" "B.Cu")
		(net "GND")
	)
	(via
		(at 307.782214 -263.616694)
		(size 0.4572)
		(drill 0.2032)
		(layers "F.Cu" "B.Cu")
		(net "GND")
	)
	(via
		(at 114.569748 -278.336502)
		(size 0.4572)
		(drill 0.2032)
		(layers "F.Cu" "B.Cu")
		(net "GND")
	)
	(via
		(at 449.677282 -272.966688)
		(size 0.4572)
		(drill 0.2032)
		(layers "F.Cu" "B.Cu")
		(net "GND")
	)
	(via
		(at 212.39734 -69.202808)
		(size 0.508)
		(drill 0.254)
		(layers "F.Cu" "B.Cu")
		(net "GND")
	)
	(via
		(at 383.655062 -266.128246)
		(size 0.4572)
		(drill 0.2032)
		(layers "F.Cu" "B.Cu")
		(net "GND")
	)
	(via
		(at 424.836082 -305.266598)
		(size 0.4572)
		(drill 0.2032)
		(layers "F.Cu" "B.Cu")
		(net "GND")
	)
	(via
		(at 411.958282 -289.966654)
		(size 0.4572)
		(drill 0.2032)
		(layers "F.Cu" "B.Cu")
		(net "GND")
	)
	(via
		(at 280.14422 -423.84726)
		(size 0.508)
		(drill 0.254)
		(layers "F.Cu" "B.Cu")
		(net "GND")
	)
	(via
		(at 448.73037 -72.778874)
		(size 0.508)
		(drill 0.254)
		(layers "F.Cu" "B.Cu")
		(net "GND")
	)
	(via
		(at 56.398414 -266.1666)
		(size 0.4572)
		(drill 0.2032)
		(layers "F.Cu" "B.Cu")
		(net "GND")
	)
	(via
		(at 118.218966 -226.017328)
		(size 0.4572)
		(drill 0.2032)
		(layers "F.Cu" "B.Cu")
		(net "GND")
	)
	(via
		(at 396.990062 -401.492212)
		(size 0.4572)
		(drill 0.254)
		(layers "F.Cu" "B.Cu")
		(net "GND")
	)
	(via
		(at 435.823614 -242.3668)
		(size 0.4572)
		(drill 0.2032)
		(layers "F.Cu" "B.Cu")
		(net "GND")
	)
	(via
		(at 101.772212 -234.970066)
		(size 0.4572)
		(drill 0.2032)
		(layers "F.Cu" "B.Cu")
		(net "GND")
	)
	(via
		(at 299.004482 -314.616592)
		(size 0.4572)
		(drill 0.2032)
		(layers "F.Cu" "B.Cu")
		(net "GND")
	)
	(via
		(at 460.664814 -208.366614)
		(size 0.4572)
		(drill 0.2032)
		(layers "F.Cu" "B.Cu")
		(net "GND")
	)
	(via
		(at 11.135614 -241.516662)
		(size 0.4572)
		(drill 0.2032)
		(layers "F.Cu" "B.Cu")
		(net "GND")
	)
	(via
		(at 115.869212 -231.714548)
		(size 0.4572)
		(drill 0.2032)
		(layers "F.Cu" "B.Cu")
		(net "GND")
	)
	(via
		(at 20.889214 -249.166634)
		(size 0.4572)
		(drill 0.2032)
		(layers "F.Cu" "B.Cu")
		(net "GND")
	)
	(via
		(at 202.971146 -244.916706)
		(size 0.4572)
		(drill 0.2032)
		(layers "F.Cu" "B.Cu")
		(net "GND")
	)
	(via
		(at 161.600134 -205.816708)
		(size 0.4572)
		(drill 0.2032)
		(layers "F.Cu" "B.Cu")
		(net "GND")
	)
	(via
		(at 14.579346 -292.516814)
		(size 0.4572)
		(drill 0.2032)
		(layers "F.Cu" "B.Cu")
		(net "GND")
	)
	(via
		(at 56.83885 -155.786074)
		(size 0.49022)
		(drill 0.254)
		(layers "F.Cu" "B.Cu")
		(net "GND")
	)
	(via
		(at 29.666946 -221.96679)
		(size 0.4572)
		(drill 0.2032)
		(layers "F.Cu" "B.Cu")
		(net "GND")
	)
	(via
		(at 325.250048 -436.051198)
		(size 0.4572)
		(drill 0.2032)
		(layers "F.Cu" "B.Cu")
		(net "GND")
	)
	(via
		(at 325.250048 -432.451256)
		(size 0.4572)
		(drill 0.2032)
		(layers "F.Cu" "B.Cu")
		(net "GND")
	)
	(via
		(at 87.785194 -257.98907)
		(size 0.4318)
		(drill 0.2032)
		(layers "F.Cu" "B.Cu")
		(net "GND")
	)
	(via
		(at 121.148094 -283.219906)
		(size 0.4572)
		(drill 0.2032)
		(layers "F.Cu" "B.Cu")
		(net "GND")
	)
	(via
		(at 367.645696 -263.277604)
		(size 0.4572)
		(drill 0.2032)
		(layers "F.Cu" "B.Cu")
		(net "GND")
	)
	(via
		(at 22.123146 -317.166752)
		(size 0.4572)
		(drill 0.2032)
		(layers "F.Cu" "B.Cu")
		(net "GND")
	)
	(via
		(at 17.36471 -112.693958)
		(size 0.508)
		(drill 0.254)
		(layers "F.Cu" "B.Cu")
		(net "GND")
	)
	(via
		(at 103.257604 -404.167848)
		(size 0.508)
		(drill 0.254)
		(layers "F.Cu" "B.Cu")
		(net "GND")
	)
	(via
		(at 262.001508 -68.616068)
		(size 0.508)
		(drill 0.254)
		(layers "F.Cu" "B.Cu")
		(net "GND")
	)
	(via
		(at 210.368388 -91.42984)
		(size 0.508)
		(drill 0.254)
		(layers "F.Cu" "B.Cu")
		(net "GND")
	)
	(via
		(at 333.26578 -242.294918)
		(size 0.4572)
		(drill 0.2032)
		(layers "F.Cu" "B.Cu")
		(net "GND")
	)
	(via
		(at 427.045882 -215.166702)
		(size 0.4572)
		(drill 0.2032)
		(layers "F.Cu" "B.Cu")
		(net "GND")
	)
	(via
		(at 102.712266 -223.575626)
		(size 0.4572)
		(drill 0.2032)
		(layers "F.Cu" "B.Cu")
		(net "GND")
	)
	(via
		(at 462.555082 -205.816708)
		(size 0.4572)
		(drill 0.2032)
		(layers "F.Cu" "B.Cu")
		(net "GND")
	)
	(via
		(at 417.602162 -360.148378)
		(size 0.49022)
		(drill 0.254)
		(layers "F.Cu" "B.Cu")
		(net "GND")
	)
	(via
		(at 266.619482 -221.116652)
		(size 0.4572)
		(drill 0.2032)
		(layers "F.Cu" "B.Cu")
		(net "GND")
	)
	(via
		(at 128.35001 -431.29962)
		(size 0.4572)
		(drill 0.2032)
		(layers "F.Cu" "B.Cu")
		(net "GND")
	)
	(via
		(at 176.896014 -262.76681)
		(size 0.4572)
		(drill 0.2032)
		(layers "F.Cu" "B.Cu")
		(net "GND")
	)
	(via
		(at 307.677312 -313.684158)
		(size 0.4572)
		(drill 0.2032)
		(layers "F.Cu" "B.Cu")
		(net "GND")
	)
	(via
		(at 323.250052 -433.899564)
		(size 0.4572)
		(drill 0.2032)
		(layers "F.Cu" "B.Cu")
		(net "GND")
	)
	(via
		(at 29.666946 -290.816792)
		(size 0.4572)
		(drill 0.2032)
		(layers "F.Cu" "B.Cu")
		(net "GND")
	)
	(via
		(at 457.221082 -272.966688)
		(size 0.4572)
		(drill 0.2032)
		(layers "F.Cu" "B.Cu")
		(net "GND")
	)
	(via
		(at 129.606548 -273.453098)
		(size 0.4572)
		(drill 0.2032)
		(layers "F.Cu" "B.Cu")
		(net "GND")
	)
	(via
		(at 84.444078 -407.00452)
		(size 0.4064)
		(drill 0.2032)
		(layers "F.Cu" "B.Cu")
		(net "GND")
	)
	(via
		(at 41.310814 -299.316648)
		(size 0.4572)
		(drill 0.2032)
		(layers "F.Cu" "B.Cu")
		(net "GND")
	)
	(via
		(at 344.296492 -333.355188)
		(size 0.49022)
		(drill 0.254)
		(layers "F.Cu" "B.Cu")
		(net "GND")
	)
	(via
		(at 167.461946 -240.666778)
		(size 0.4572)
		(drill 0.2032)
		(layers "F.Cu" "B.Cu")
		(net "GND")
	)
	(via
		(at 432.50104 -121.464578)
		(size 0.508)
		(drill 0.254)
		(layers "F.Cu" "B.Cu")
		(net "GND")
	)
	(via
		(at 135.714994 -275.8948)
		(size 0.4572)
		(drill 0.2032)
		(layers "F.Cu" "B.Cu")
		(net "GND")
	)
	(via
		(at 154.81808 -130.851148)
		(size 0.508)
		(drill 0.254)
		(layers "F.Cu" "B.Cu")
		(net "GND")
	)
	(via
		(at 88.590882 -339.114638)
		(size 0.49022)
		(drill 0.254)
		(layers "F.Cu" "B.Cu")
		(net "GND")
	)
	(via
		(at 464.53552 -423.31513)
		(size 0.508)
		(drill 0.254)
		(layers "F.Cu" "B.Cu")
		(net "GND")
	)
	(via
		(at 260.95198 -422.9608)
		(size 0.508)
		(drill 0.254)
		(layers "F.Cu" "B.Cu")
		(net "GND")
	)
	(via
		(at 20.889214 -194.766692)
		(size 0.4572)
		(drill 0.2032)
		(layers "F.Cu" "B.Cu")
		(net "GND")
	)
	(via
		(at 261.285482 -282.316682)
		(size 0.4572)
		(drill 0.2032)
		(layers "F.Cu" "B.Cu")
		(net "GND")
	)
	(via
		(at 268.829282 -308.666642)
		(size 0.4572)
		(drill 0.2032)
		(layers "F.Cu" "B.Cu")
		(net "GND")
	)
	(via
		(at 86.161118 -403.883876)
		(size 0.4064)
		(drill 0.2032)
		(layers "F.Cu" "B.Cu")
		(net "GND")
	)
	(via
		(at 356.62616 -329.76312)
		(size 0.508)
		(drill 0.254)
		(layers "F.Cu" "B.Cu")
		(net "GND")
	)
	(via
		(at 18.311114 -6.597396)
		(size 0.508)
		(drill 0.254)
		(layers "F.Cu" "B.Cu")
		(net "GND")
	)
	(via
		(at 102.90683 -240.344706)
		(size 0.4572)
		(drill 0.2032)
		(layers "F.Cu" "B.Cu")
		(net "GND")
	)
	(via
		(at 26.223214 -275.516594)
		(size 0.4572)
		(drill 0.2032)
		(layers "F.Cu" "B.Cu")
		(net "GND")
	)
	(via
		(at 51.064414 -226.216718)
		(size 0.4572)
		(drill 0.2032)
		(layers "F.Cu" "B.Cu")
		(net "GND")
	)
	(via
		(at 128.947926 -335.976214)
		(size 0.49022)
		(drill 0.254)
		(layers "F.Cu" "B.Cu")
		(net "GND")
	)
	(via
		(at 205.180946 -295.06672)
		(size 0.4572)
		(drill 0.2032)
		(layers "F.Cu" "B.Cu")
		(net "GND")
	)
	(via
		(at 51.064414 -213.46668)
		(size 0.4572)
		(drill 0.2032)
		(layers "F.Cu" "B.Cu")
		(net "GND")
	)
	(via
		(at 138.064748 -283.219906)
		(size 0.4572)
		(drill 0.2032)
		(layers "F.Cu" "B.Cu")
		(net "GND")
	)
	(via
		(at 310.893968 -407.00452)
		(size 0.4064)
		(drill 0.2032)
		(layers "F.Cu" "B.Cu")
		(net "GND")
	)
	(via
		(at 259.075682 -239.81664)
		(size 0.4572)
		(drill 0.2032)
		(layers "F.Cu" "B.Cu")
		(net "GND")
	)
	(via
		(at 91.434666 -223.575626)
		(size 0.4572)
		(drill 0.2032)
		(layers "F.Cu" "B.Cu")
		(net "GND")
	)
	(via
		(at 23.760938 -175.83404)
		(size 0.508)
		(drill 0.254)
		(layers "F.Cu" "B.Cu")
		(net "GND")
	)
	(via
		(at 358.640634 -229.272846)
		(size 0.4572)
		(drill 0.2032)
		(layers "F.Cu" "B.Cu")
		(net "GND")
	)
	(via
		(at 299.004482 -269.566644)
		(size 0.4572)
		(drill 0.2032)
		(layers "F.Cu" "B.Cu")
		(net "GND")
	)
	(via
		(at 304.338482 -297.616626)
		(size 0.4572)
		(drill 0.2032)
		(layers "F.Cu" "B.Cu")
		(net "GND")
	)
	(via
		(at 51.064414 -247.466612)
		(size 0.4572)
		(drill 0.2032)
		(layers "F.Cu" "B.Cu")
		(net "GND")
	)
	(via
		(at 62.267846 -285.716726)
		(size 0.4572)
		(drill 0.2032)
		(layers "F.Cu" "B.Cu")
		(net "GND")
	)
	(via
		(at 378.697998 -410.664152)
		(size 0.4572)
		(drill 0.254)
		(layers "F.Cu" "B.Cu")
		(net "GND")
	)
	(via
		(at 356.51821 -360.753406)
		(size 0.508)
		(drill 0.254)
		(layers "F.Cu" "B.Cu")
		(net "GND")
	)
	(via
		(at 422.945814 -295.06672)
		(size 0.4572)
		(drill 0.2032)
		(layers "F.Cu" "B.Cu")
		(net "GND")
	)
	(via
		(at 291.460682 -271.266666)
		(size 0.4572)
		(drill 0.2032)
		(layers "F.Cu" "B.Cu")
		(net "GND")
	)
	(via
		(at 120.97639 -255.530604)
		(size 0.4572)
		(drill 0.2032)
		(layers "F.Cu" "B.Cu")
		(net "GND")
	)
	(via
		(at 195.427346 -197.316598)
		(size 0.4572)
		(drill 0.2032)
		(layers "F.Cu" "B.Cu")
		(net "GND")
	)
	(via
		(at 403.349968 -433.899564)
		(size 0.4572)
		(drill 0.2032)
		(layers "F.Cu" "B.Cu")
		(net "GND")
	)
	(via
		(at 126.238508 -22.394418)
		(size 0.508)
		(drill 0.254)
		(layers "F.Cu" "B.Cu")
		(net "GND")
	)
	(via
		(at 115.508278 -332.570074)
		(size 0.49022)
		(drill 0.254)
		(layers "F.Cu" "B.Cu")
		(net "GND")
	)
	(via
		(at 331.881988 -55.498746)
		(size 0.4572)
		(drill 0.2032)
		(layers "F.Cu" "B.Cu")
		(net "GND")
	)
	(via
		(at 272.273014 -289.11677)
		(size 0.4572)
		(drill 0.2032)
		(layers "F.Cu" "B.Cu")
		(net "GND")
	)
	(via
		(at 371.32768 -230.086662)
		(size 0.4572)
		(drill 0.2032)
		(layers "F.Cu" "B.Cu")
		(net "GND")
	)
	(via
		(at 190.093346 -292.516814)
		(size 0.4572)
		(drill 0.2032)
		(layers "F.Cu" "B.Cu")
		(net "GND")
	)
	(via
		(at 9.245346 -199.01662)
		(size 0.4572)
		(drill 0.2032)
		(layers "F.Cu" "B.Cu")
		(net "GND")
	)
	(via
		(at 457.221082 -213.46668)
		(size 0.4572)
		(drill 0.2032)
		(layers "F.Cu" "B.Cu")
		(net "GND")
	)
	(via
		(at 337.604862 -271.011396)
		(size 0.4572)
		(drill 0.2032)
		(layers "F.Cu" "B.Cu")
		(net "GND")
	)
	(via
		(at 176.155604 -114.17554)
		(size 0.4572)
		(drill 0.254)
		(layers "F.Cu" "B.Cu")
		(net "GND")
	)
	(via
		(at 291.460682 -202.416664)
		(size 0.4572)
		(drill 0.2032)
		(layers "F.Cu" "B.Cu")
		(net "GND")
	)
	(via
		(at 106.001566 -222.761556)
		(size 0.4572)
		(drill 0.2032)
		(layers "F.Cu" "B.Cu")
		(net "GND")
	)
	(via
		(at 114.099594 -274.266914)
		(size 0.4572)
		(drill 0.2032)
		(layers "F.Cu" "B.Cu")
		(net "GND")
	)
	(via
		(at 259.075682 -207.51673)
		(size 0.4572)
		(drill 0.2032)
		(layers "F.Cu" "B.Cu")
		(net "GND")
	)
	(via
		(at 131.829302 -335.980278)
		(size 0.49022)
		(drill 0.254)
		(layers "F.Cu" "B.Cu")
		(net "GND")
	)
	(via
		(at 274.163282 -291.666676)
		(size 0.4572)
		(drill 0.2032)
		(layers "F.Cu" "B.Cu")
		(net "GND")
	)
	(via
		(at 358.42321 -356.943406)
		(size 0.508)
		(drill 0.254)
		(layers "F.Cu" "B.Cu")
		(net "GND")
	)
	(via
		(at 37.210746 -292.516814)
		(size 0.4572)
		(drill 0.2032)
		(layers "F.Cu" "B.Cu")
		(net "GND")
	)
	(via
		(at 408.152092 -227.066602)
		(size 0.4572)
		(drill 0.2032)
		(layers "F.Cu" "B.Cu")
		(net "GND")
	)
	(via
		(at 133.469126 -400.224244)
		(size 0.4572)
		(drill 0.254)
		(layers "F.Cu" "B.Cu")
		(net "GND")
	)
	(via
		(at 33.767014 -249.166634)
		(size 0.4572)
		(drill 0.2032)
		(layers "F.Cu" "B.Cu")
		(net "GND")
	)
	(via
		(at 171.562014 -233.86669)
		(size 0.4572)
		(drill 0.2032)
		(layers "F.Cu" "B.Cu")
		(net "GND")
	)
	(via
		(at 130.405886 -401.492212)
		(size 0.4572)
		(drill 0.254)
		(layers "F.Cu" "B.Cu")
		(net "GND")
	)
	(via
		(at 186.649614 -277.216616)
		(size 0.4572)
		(drill 0.2032)
		(layers "F.Cu" "B.Cu")
		(net "GND")
	)
	(via
		(at 131.547108 -17.655032)
		(size 0.508)
		(drill 0.254)
		(layers "F.Cu" "B.Cu")
		(net "GND")
	)
	(via
		(at 19.39671 -177.607976)
		(size 0.508)
		(drill 0.254)
		(layers "F.Cu" "B.Cu")
		(net "GND")
	)
	(via
		(at 365.798862 -266.128246)
		(size 0.4572)
		(drill 0.2032)
		(layers "F.Cu" "B.Cu")
		(net "GND")
	)
	(via
		(at 162.384486 -406.370536)
		(size 0.4572)
		(drill 0.254)
		(layers "F.Cu" "B.Cu")
		(net "GND")
	)
	(via
		(at 378.956062 -256.361438)
		(size 0.4572)
		(drill 0.2032)
		(layers "F.Cu" "B.Cu")
		(net "GND")
	)
	(via
		(at 309.811928 -410.030168)
		(size 0.4064)
		(drill 0.2032)
		(layers "F.Cu" "B.Cu")
		(net "GND")
	)
	(via
		(at 128.666748 -265.314176)
		(size 0.4572)
		(drill 0.2032)
		(layers "F.Cu" "B.Cu")
		(net "GND")
	)
	(via
		(at 179.105814 -278.916638)
		(size 0.4572)
		(drill 0.2032)
		(layers "F.Cu" "B.Cu")
		(net "GND")
	)
	(via
		(at 52.298346 -301.866808)
		(size 0.4572)
		(drill 0.2032)
		(layers "F.Cu" "B.Cu")
		(net "GND")
	)
	(via
		(at 322.161916 -401.492212)
		(size 0.4572)
		(drill 0.254)
		(layers "F.Cu" "B.Cu")
		(net "GND")
	)
	(via
		(at 447.439288 -183.009032)
		(size 0.508)
		(drill 0.254)
		(layers "F.Cu" "B.Cu")
		(net "GND")
	)
	(via
		(at 205.180946 -217.716608)
		(size 0.4572)
		(drill 0.2032)
		(layers "F.Cu" "B.Cu")
		(net "GND")
	)
	(via
		(at 365.983266 -338.60359)
		(size 0.508)
		(drill 0.254)
		(layers "F.Cu" "B.Cu")
		(net "GND")
	)
	(via
		(at 177.75555 -114.975386)
		(size 0.4572)
		(drill 0.254)
		(layers "F.Cu" "B.Cu")
		(net "GND")
	)
	(via
		(at 107.881166 -222.761556)
		(size 0.4572)
		(drill 0.2032)
		(layers "F.Cu" "B.Cu")
		(net "GND")
	)
	(via
		(at 184.246012 -410.083762)
		(size 0.508)
		(drill 0.254)
		(layers "F.Cu" "B.Cu")
		(net "GND")
	)
	(via
		(at 209.281014 -303.566576)
		(size 0.4572)
		(drill 0.2032)
		(layers "F.Cu" "B.Cu")
		(net "GND")
	)
	(via
		(at 216.824814 -289.966654)
		(size 0.4572)
		(drill 0.2032)
		(layers "F.Cu" "B.Cu")
		(net "GND")
	)
	(via
		(at 39.420546 -304.416714)
		(size 0.4572)
		(drill 0.2032)
		(layers "F.Cu" "B.Cu")
		(net "GND")
	)
	(via
		(at 203.76388 -100.006658)
		(size 0.508)
		(drill 0.254)
		(layers "F.Cu" "B.Cu")
		(net "GND")
	)
	(via
		(at 56.398414 -262.76681)
		(size 0.4572)
		(drill 0.2032)
		(layers "F.Cu" "B.Cu")
		(net "GND")
	)
	(via
		(at 44.754546 -248.31675)
		(size 0.4572)
		(drill 0.2032)
		(layers "F.Cu" "B.Cu")
		(net "GND")
	)
	(via
		(at 287.384236 -319.351914)
		(size 0.4572)
		(drill 0.2032)
		(layers "F.Cu" "B.Cu")
		(net "GND")
	)
	(via
		(at 191.983614 -258.516628)
		(size 0.4572)
		(drill 0.2032)
		(layers "F.Cu" "B.Cu")
		(net "GND")
	)
	(via
		(at 376.22734 -335.187036)
		(size 0.49022)
		(drill 0.254)
		(layers "F.Cu" "B.Cu")
		(net "GND")
	)
	(via
		(at 464.764882 -238.116618)
		(size 0.4572)
		(drill 0.2032)
		(layers "F.Cu" "B.Cu")
		(net "GND")
	)
	(via
		(at 176.896014 -271.266666)
		(size 0.4572)
		(drill 0.2032)
		(layers "F.Cu" "B.Cu")
		(net "GND")
	)
	(via
		(at 281.707082 -194.766692)
		(size 0.4572)
		(drill 0.2032)
		(layers "F.Cu" "B.Cu")
		(net "GND")
	)
	(via
		(at 117.859048 -282.405836)
		(size 0.4572)
		(drill 0.2032)
		(layers "F.Cu" "B.Cu")
		(net "GND")
	)
	(via
		(at 348.77248 -243.108988)
		(size 0.4572)
		(drill 0.2032)
		(layers "F.Cu" "B.Cu")
		(net "GND")
	)
	(via
		(at 276.373082 -306.96662)
		(size 0.4572)
		(drill 0.2032)
		(layers "F.Cu" "B.Cu")
		(net "GND")
	)
	(via
		(at 366.2172 -414.7566)
		(size 0.508)
		(drill 0.254)
		(layers "F.Cu" "B.Cu")
		(net "GND")
	)
	(via
		(at 373.677434 -230.900478)
		(size 0.4572)
		(drill 0.2032)
		(layers "F.Cu" "B.Cu")
		(net "GND")
	)
	(via
		(at 199.527414 -303.566576)
		(size 0.4572)
		(drill 0.2032)
		(layers "F.Cu" "B.Cu")
		(net "GND")
	)
	(via
		(at 48.854614 -222.816674)
		(size 0.4572)
		(drill 0.2032)
		(layers "F.Cu" "B.Cu")
		(net "GND")
	)
	(via
		(at 23.0378 -76.266548)
		(size 0.508)
		(drill 0.254)
		(layers "F.Cu" "B.Cu")
		(net "GND")
	)
	(via
		(at 98.483166 -227.64496)
		(size 0.4572)
		(drill 0.2032)
		(layers "F.Cu" "B.Cu")
		(net "GND")
	)
	(via
		(at 294.904414 -236.416596)
		(size 0.4572)
		(drill 0.2032)
		(layers "F.Cu" "B.Cu")
		(net "GND")
	)
	(via
		(at 31.876746 -208.366614)
		(size 0.4572)
		(drill 0.2032)
		(layers "F.Cu" "B.Cu")
		(net "GND")
	)
	(via
		(at 362.87456 -58.425588)
		(size 0.508)
		(drill 0.254)
		(layers "F.Cu" "B.Cu")
		(net "GND")
	)
	(via
		(at 214.615014 -297.616626)
		(size 0.4572)
		(drill 0.2032)
		(layers "F.Cu" "B.Cu")
		(net "GND")
	)
	(via
		(at 385.894834 -230.900478)
		(size 0.4318)
		(drill 0.2032)
		(layers "F.Cu" "B.Cu")
		(net "GND")
	)
	(via
		(at 56.83885 -147.810474)
		(size 0.49022)
		(drill 0.254)
		(layers "F.Cu" "B.Cu")
		(net "GND")
	)
	(via
		(at 83.55711 -60.252356)
		(size 0.508)
		(drill 0.254)
		(layers "F.Cu" "B.Cu")
		(net "GND")
	)
	(via
		(at 377.43638 -239.0394)
		(size 0.4572)
		(drill 0.2032)
		(layers "F.Cu" "B.Cu")
		(net "GND")
	)
	(via
		(at 363.281976 -236.564932)
		(size 0.4572)
		(drill 0.2032)
		(layers "F.Cu" "B.Cu")
		(net "GND")
	)
	(via
		(at 115.399566 -222.761556)
		(size 0.4572)
		(drill 0.2032)
		(layers "F.Cu" "B.Cu")
		(net "GND")
	)
	(via
		(at 330.252578 -50.799746)
		(size 0.4572)
		(drill 0.2032)
		(layers "F.Cu" "B.Cu")
		(net "GND")
	)
	(via
		(at 344.07348 -243.108988)
		(size 0.4572)
		(drill 0.2032)
		(layers "F.Cu" "B.Cu")
		(net "GND")
	)
	(via
		(at 25.510998 -6.597396)
		(size 0.508)
		(drill 0.254)
		(layers "F.Cu" "B.Cu")
		(net "GND")
	)
	(via
		(at 24.332946 -236.416596)
		(size 0.4572)
		(drill 0.2032)
		(layers "F.Cu" "B.Cu")
		(net "GND")
	)
	(via
		(at 31.876746 -240.666778)
		(size 0.4572)
		(drill 0.2032)
		(layers "F.Cu" "B.Cu")
		(net "GND")
	)
	(via
		(at 314.092082 -277.216616)
		(size 0.4572)
		(drill 0.2032)
		(layers "F.Cu" "B.Cu")
		(net "GND")
	)
	(via
		(at 92.013786 -407.638504)
		(size 0.4572)
		(drill 0.254)
		(layers "F.Cu" "B.Cu")
		(net "GND")
	)
	(via
		(at 55.343806 -5.596636)
		(size 0.508)
		(drill 0.254)
		(layers "F.Cu" "B.Cu")
		(net "GND")
	)
	(via
		(at 386.82168 -28.70962)
		(size 0.508)
		(drill 0.254)
		(layers "F.Cu" "B.Cu")
		(net "GND")
	)
	(via
		(at 458.455014 -304.416714)
		(size 0.4572)
		(drill 0.2032)
		(layers "F.Cu" "B.Cu")
		(net "GND")
	)
	(via
		(at 93.314266 -213.732618)
		(size 0.4572)
		(drill 0.2032)
		(layers "F.Cu" "B.Cu")
		(net "GND")
	)
	(via
		(at 201.737214 -306.96662)
		(size 0.4572)
		(drill 0.2032)
		(layers "F.Cu" "B.Cu")
		(net "GND")
	)
	(via
		(at 18.679414 -299.316648)
		(size 0.4572)
		(drill 0.2032)
		(layers "F.Cu" "B.Cu")
		(net "GND")
	)
	(via
		(at 294.077644 -355.156008)
		(size 0.508)
		(drill 0.254)
		(layers "F.Cu" "B.Cu")
		(net "GND")
	)
	(via
		(at 18.650966 -398.782032)
		(size 0.508)
		(drill 0.254)
		(layers "F.Cu" "B.Cu")
		(net "GND")
	)
	(via
		(at 40.27678 -386.329174)
		(size 0.508)
		(drill 0.254)
		(layers "F.Cu" "B.Cu")
		(net "GND")
	)
	(via
		(at 422.55186 -358.754172)
		(size 0.508)
		(drill 0.254)
		(layers "F.Cu" "B.Cu")
		(net "GND")
	)
	(via
		(at 82.74177 -58.602626)
		(size 0.508)
		(drill 0.254)
		(layers "F.Cu" "B.Cu")
		(net "GND")
	)
	(via
		(at 450.911214 -263.616694)
		(size 0.4572)
		(drill 0.2032)
		(layers "F.Cu" "B.Cu")
		(net "GND")
	)
	(via
		(at 89.194894 -284.847538)
		(size 0.4572)
		(drill 0.2032)
		(layers "F.Cu" "B.Cu")
		(net "GND")
	)
	(via
		(at 292.694614 -201.56678)
		(size 0.4572)
		(drill 0.2032)
		(layers "F.Cu" "B.Cu")
		(net "GND")
	)
	(via
		(at 156.716222 -401.492212)
		(size 0.4572)
		(drill 0.254)
		(layers "F.Cu" "B.Cu")
		(net "GND")
	)
	(via
		(at 364.279434 -216.25052)
		(size 0.4572)
		(drill 0.2032)
		(layers "F.Cu" "B.Cu")
		(net "GND")
	)
	(via
		(at 172.795946 -250.016772)
		(size 0.4572)
		(drill 0.2032)
		(layers "F.Cu" "B.Cu")
		(net "GND")
	)
	(via
		(at 132.315712 -235.783882)
		(size 0.4572)
		(drill 0.2032)
		(layers "F.Cu" "B.Cu")
		(net "GND")
	)
	(via
		(at 243.727732 -134.458456)
		(size 0.508)
		(drill 0.254)
		(layers "F.Cu" "B.Cu")
		(net "GND")
	)
	(via
		(at 382.135634 -234.15625)
		(size 0.4572)
		(drill 0.2032)
		(layers "F.Cu" "B.Cu")
		(net "GND")
	)
	(via
		(at 46.964346 -233.016806)
		(size 0.4572)
		(drill 0.2032)
		(layers "F.Cu" "B.Cu")
		(net "GND")
	)
	(via
		(at 96.133412 -243.108988)
		(size 0.4572)
		(drill 0.2032)
		(layers "F.Cu" "B.Cu")
		(net "GND")
	)
	(via
		(at 308.10454 -400.224244)
		(size 0.4572)
		(drill 0.254)
		(layers "F.Cu" "B.Cu")
		(net "GND")
	)
	(via
		(at 135.714994 -274.266914)
		(size 0.4572)
		(drill 0.2032)
		(layers "F.Cu" "B.Cu")
		(net "GND")
	)
	(via
		(at 216.824814 -275.516594)
		(size 0.4572)
		(drill 0.2032)
		(layers "F.Cu" "B.Cu")
		(net "GND")
	)
	(via
		(at 443.367414 -244.916706)
		(size 0.4572)
		(drill 0.2032)
		(layers "F.Cu" "B.Cu")
		(net "GND")
	)
	(via
		(at 113.52022 -247.178576)
		(size 0.4572)
		(drill 0.2032)
		(layers "F.Cu" "B.Cu")
		(net "GND")
	)
	(via
		(at 111.640112 -217.878406)
		(size 0.4572)
		(drill 0.2032)
		(layers "F.Cu" "B.Cu")
		(net "GND")
	)
	(via
		(at 347.127068 -331.780896)
		(size 0.49022)
		(drill 0.254)
		(layers "F.Cu" "B.Cu")
		(net "GND")
	)
	(via
		(at 88.145366 -226.017328)
		(size 0.4572)
		(drill 0.2032)
		(layers "F.Cu" "B.Cu")
		(net "GND")
	)
	(via
		(at 22.123146 -307.816758)
		(size 0.4572)
		(drill 0.2032)
		(layers "F.Cu" "B.Cu")
		(net "GND")
	)
	(via
		(at 294.904414 -244.916706)
		(size 0.4572)
		(drill 0.2032)
		(layers "F.Cu" "B.Cu")
		(net "GND")
	)
	(via
		(at 434.589682 -205.816708)
		(size 0.4572)
		(drill 0.2032)
		(layers "F.Cu" "B.Cu")
		(net "GND")
	)
	(via
		(at 159.918146 -197.316598)
		(size 0.4572)
		(drill 0.2032)
		(layers "F.Cu" "B.Cu")
		(net "GND")
	)
	(via
		(at 46.964346 -229.616762)
		(size 0.4572)
		(drill 0.2032)
		(layers "F.Cu" "B.Cu")
		(net "GND")
	)
	(via
		(at 26.223214 -306.96662)
		(size 0.4572)
		(drill 0.2032)
		(layers "F.Cu" "B.Cu")
		(net "GND")
	)
	(via
		(at 202.971146 -250.016772)
		(size 0.4572)
		(drill 0.2032)
		(layers "F.Cu" "B.Cu")
		(net "GND")
	)
	(via
		(at 422.945814 -298.466764)
		(size 0.4572)
		(drill 0.2032)
		(layers "F.Cu" "B.Cu")
		(net "GND")
	)
	(via
		(at 417.292282 -295.916604)
		(size 0.4572)
		(drill 0.2032)
		(layers "F.Cu" "B.Cu")
		(net "GND")
	)
	(via
		(at 43.47972 -102.07879)
		(size 0.508)
		(drill 0.254)
		(layers "F.Cu" "B.Cu")
		(net "GND")
	)
	(via
		(at 210.514946 -221.96679)
		(size 0.4572)
		(drill 0.2032)
		(layers "F.Cu" "B.Cu")
		(net "GND")
	)
	(via
		(at 247.824752 -38.0873)
		(size 0.508)
		(drill 0.254)
		(layers "F.Cu" "B.Cu")
		(net "GND")
	)
	(via
		(at 339.014562 -257.175254)
		(size 0.4572)
		(drill 0.2032)
		(layers "F.Cu" "B.Cu")
		(net "GND")
	)
	(via
		(at 97.073466 -217.064336)
		(size 0.4572)
		(drill 0.2032)
		(layers "F.Cu" "B.Cu")
		(net "GND")
	)
	(via
		(at 214.615014 -200.716642)
		(size 0.4572)
		(drill 0.2032)
		(layers "F.Cu" "B.Cu")
		(net "GND")
	)
	(via
		(at 251.738638 -134.595108)
		(size 0.508)
		(drill 0.254)
		(layers "F.Cu" "B.Cu")
		(net "GND")
	)
	(via
		(at 302.650652 -322.581016)
		(size 0.4572)
		(drill 0.2032)
		(layers "F.Cu" "B.Cu")
		(net "GND")
	)
	(via
		(at 347.805248 -329.76312)
		(size 0.508)
		(drill 0.254)
		(layers "F.Cu" "B.Cu")
		(net "GND")
	)
	(via
		(at 285.150814 -258.516628)
		(size 0.4572)
		(drill 0.2032)
		(layers "F.Cu" "B.Cu")
		(net "GND")
	)
	(via
		(at 356.373684 -258.994148)
		(size 0.4572)
		(drill 0.2032)
		(layers "F.Cu" "B.Cu")
		(net "GND")
	)
	(via
		(at 24.332946 -231.316784)
		(size 0.4572)
		(drill 0.2032)
		(layers "F.Cu" "B.Cu")
		(net "GND")
	)
	(via
		(at 464.764882 -262.76681)
		(size 0.4572)
		(drill 0.2032)
		(layers "F.Cu" "B.Cu")
		(net "GND")
	)
	(via
		(at 279.816814 -221.96679)
		(size 0.4572)
		(drill 0.2032)
		(layers "F.Cu" "B.Cu")
		(net "GND")
	)
	(via
		(at 136.176258 -62.903608)
		(size 0.508)
		(drill 0.254)
		(layers "F.Cu" "B.Cu")
		(net "GND")
	)
	(via
		(at 241.643916 -53.196998)
		(size 0.508)
		(drill 0.254)
		(layers "F.Cu" "B.Cu")
		(net "GND")
	)
	(via
		(at 175.005746 -231.316784)
		(size 0.4572)
		(drill 0.2032)
		(layers "F.Cu" "B.Cu")
		(net "GND")
	)
	(via
		(at 199.527414 -216.866724)
		(size 0.4572)
		(drill 0.2032)
		(layers "F.Cu" "B.Cu")
		(net "GND")
	)
	(via
		(at 467.535514 -378.32538)
		(size 0.508)
		(drill 0.254)
		(layers "F.Cu" "B.Cu")
		(net "GND")
	)
	(via
		(at 438.033414 -295.06672)
		(size 0.4572)
		(drill 0.2032)
		(layers "F.Cu" "B.Cu")
		(net "GND")
	)
	(via
		(at 44.754546 -203.266802)
		(size 0.4572)
		(drill 0.2032)
		(layers "F.Cu" "B.Cu")
		(net "GND")
	)
	(via
		(at 76.250038 -426.69968)
		(size 0.4572)
		(drill 0.2032)
		(layers "F.Cu" "B.Cu")
		(net "GND")
	)
	(via
		(at 292.285928 -360.762804)
		(size 0.508)
		(drill 0.254)
		(layers "F.Cu" "B.Cu")
		(net "GND")
	)
	(via
		(at 202.971146 -204.96657)
		(size 0.4572)
		(drill 0.2032)
		(layers "F.Cu" "B.Cu")
		(net "GND")
	)
	(via
		(at 314.092082 -230.466646)
		(size 0.4572)
		(drill 0.2032)
		(layers "F.Cu" "B.Cu")
		(net "GND")
	)
	(via
		(at 153.34996 -438.499758)
		(size 0.4572)
		(drill 0.2032)
		(layers "F.Cu" "B.Cu")
		(net "GND")
	)
	(via
		(at 137.878566 -406.370536)
		(size 0.4572)
		(drill 0.254)
		(layers "F.Cu" "B.Cu")
		(net "GND")
	)
	(via
		(at 2.764536 -183.310022)
		(size 0.508)
		(drill 0.254)
		(layers "F.Cu" "B.Cu")
		(net "GND")
	)
	(via
		(at 9.245346 -309.51678)
		(size 0.4572)
		(drill 0.2032)
		(layers "F.Cu" "B.Cu")
		(net "GND")
	)
	(via
		(at 460.664814 -199.01662)
		(size 0.4572)
		(drill 0.2032)
		(layers "F.Cu" "B.Cu")
		(net "GND")
	)
	(via
		(at 302.448214 -227.066602)
		(size 0.4572)
		(drill 0.2032)
		(layers "F.Cu" "B.Cu")
		(net "GND")
	)
	(via
		(at 53.547518 -403.883876)
		(size 0.4064)
		(drill 0.2032)
		(layers "F.Cu" "B.Cu")
		(net "GND")
	)
	(via
		(at 115.382802 -249.227086)
		(size 0.4572)
		(drill 0.2032)
		(layers "F.Cu" "B.Cu")
		(net "GND")
	)
	(via
		(at 403.349968 -426.69968)
		(size 0.4572)
		(drill 0.2032)
		(layers "F.Cu" "B.Cu")
		(net "GND")
	)
	(via
		(at 435.823614 -276.366732)
		(size 0.4572)
		(drill 0.2032)
		(layers "F.Cu" "B.Cu")
		(net "GND")
	)
	(via
		(at 66.152014 -202.416664)
		(size 0.4572)
		(drill 0.2032)
		(layers "F.Cu" "B.Cu")
		(net "GND")
	)
	(via
		(at 19.84248 -384.285744)
		(size 0.508)
		(drill 0.254)
		(layers "F.Cu" "B.Cu")
		(net "GND")
	)
	(via
		(at 26.223214 -299.316648)
		(size 0.4572)
		(drill 0.2032)
		(layers "F.Cu" "B.Cu")
		(net "GND")
	)
	(via
		(at 202.971146 -265.316716)
		(size 0.4572)
		(drill 0.2032)
		(layers "F.Cu" "B.Cu")
		(net "GND")
	)
	(via
		(at 311.882282 -241.516662)
		(size 0.4572)
		(drill 0.2032)
		(layers "F.Cu" "B.Cu")
		(net "GND")
	)
	(via
		(at 414.646618 -149.972776)
		(size 0.508)
		(drill 0.254)
		(layers "F.Cu" "B.Cu")
		(net "GND")
	)
	(via
		(at 7.035546 -242.3668)
		(size 0.4572)
		(drill 0.2032)
		(layers "F.Cu" "B.Cu")
		(net "GND")
	)
	(via
		(at 56.834786 -150.03145)
		(size 0.49022)
		(drill 0.254)
		(layers "F.Cu" "B.Cu")
		(net "GND")
	)
	(via
		(at 54.508146 -268.71676)
		(size 0.4572)
		(drill 0.2032)
		(layers "F.Cu" "B.Cu")
		(net "GND")
	)
	(via
		(at 176.896014 -221.116652)
		(size 0.4572)
		(drill 0.2032)
		(layers "F.Cu" "B.Cu")
		(net "GND")
	)
	(via
		(at 129.026412 -238.225584)
		(size 0.4572)
		(drill 0.2032)
		(layers "F.Cu" "B.Cu")
		(net "GND")
	)
	(via
		(at 413.349948 -438.499758)
		(size 0.4572)
		(drill 0.2032)
		(layers "F.Cu" "B.Cu")
		(net "GND")
	)
	(via
		(at 396.349982 -432.451256)
		(size 0.4572)
		(drill 0.2032)
		(layers "F.Cu" "B.Cu")
		(net "GND")
	)
	(via
		(at 141.049502 -340.466172)
		(size 0.508)
		(drill 0.254)
		(layers "F.Cu" "B.Cu")
		(net "GND")
	)
	(via
		(at 266.619482 -258.516628)
		(size 0.4572)
		(drill 0.2032)
		(layers "F.Cu" "B.Cu")
		(net "GND")
	)
	(via
		(at 289.250882 -264.466578)
		(size 0.4572)
		(drill 0.2032)
		(layers "F.Cu" "B.Cu")
		(net "GND")
	)
	(via
		(at 141.367002 -339.170772)
		(size 0.508)
		(drill 0.254)
		(layers "F.Cu" "B.Cu")
		(net "GND")
	)
	(via
		(at 239.70488 -250.386088)
		(size 0.508)
		(drill 0.254)
		(layers "F.Cu" "B.Cu")
		(net "GND")
	)
	(via
		(at 407.858214 -210.916774)
		(size 0.4572)
		(drill 0.2032)
		(layers "F.Cu" "B.Cu")
		(net "GND")
	)
	(via
		(at 261.285482 -244.066568)
		(size 0.4572)
		(drill 0.2032)
		(layers "F.Cu" "B.Cu")
		(net "GND")
	)
	(via
		(at 171.562014 -278.916638)
		(size 0.4572)
		(drill 0.2032)
		(layers "F.Cu" "B.Cu")
		(net "GND")
	)
	(via
		(at 279.816814 -289.11677)
		(size 0.4572)
		(drill 0.2032)
		(layers "F.Cu" "B.Cu")
		(net "GND")
	)
	(via
		(at 300.022514 -295.06672)
		(size 0.4572)
		(drill 0.2032)
		(layers "F.Cu" "B.Cu")
		(net "GND")
	)
	(via
		(at 350.762062 -269.38351)
		(size 0.4572)
		(drill 0.2032)
		(layers "F.Cu" "B.Cu")
		(net "GND")
	)
	(via
		(at 151.935942 -406.370536)
		(size 0.4572)
		(drill 0.254)
		(layers "F.Cu" "B.Cu")
		(net "GND")
	)
	(via
		(at 59.842146 -263.616694)
		(size 0.4572)
		(drill 0.2032)
		(layers "F.Cu" "B.Cu")
		(net "GND")
	)
	(via
		(at 164.018214 -262.76681)
		(size 0.4572)
		(drill 0.2032)
		(layers "F.Cu" "B.Cu")
		(net "GND")
	)
	(via
		(at 144.695672 -58.372248)
		(size 0.508)
		(drill 0.254)
		(layers "F.Cu" "B.Cu")
		(net "GND")
	)
	(via
		(at 350.774762 -251.135134)
		(size 0.4572)
		(drill 0.2032)
		(layers "F.Cu" "B.Cu")
		(net "GND")
	)
	(via
		(at 302.372776 -360.777536)
		(size 0.508)
		(drill 0.254)
		(layers "F.Cu" "B.Cu")
		(net "GND")
	)
	(via
		(at 159.82188 -122.646948)
		(size 0.508)
		(drill 0.254)
		(layers "F.Cu" "B.Cu")
		(net "GND")
	)
	(via
		(at 109.870494 -273.453098)
		(size 0.4572)
		(drill 0.2032)
		(layers "F.Cu" "B.Cu")
		(net "GND")
	)
	(via
		(at 298.66082 -417.990528)
		(size 0.508)
		(drill 0.254)
		(layers "F.Cu" "B.Cu")
		(net "GND")
	)
	(via
		(at 168.872154 -407.00452)
		(size 0.4064)
		(drill 0.2032)
		(layers "F.Cu" "B.Cu")
		(net "GND")
	)
	(via
		(at 412.306262 -403.249892)
		(size 0.4572)
		(drill 0.254)
		(layers "F.Cu" "B.Cu")
		(net "GND")
	)
	(via
		(at 108.43387 -256.33045)
		(size 0.4572)
		(drill 0.2032)
		(layers "F.Cu" "B.Cu")
		(net "GND")
	)
	(via
		(at 292.694614 -216.016586)
		(size 0.4572)
		(drill 0.2032)
		(layers "F.Cu" "B.Cu")
		(net "GND")
	)
	(via
		(at 419.590474 -137.178034)
		(size 0.508)
		(drill 0.254)
		(layers "F.Cu" "B.Cu")
		(net "GND")
	)
	(via
		(at 175.005746 -248.31675)
		(size 0.4572)
		(drill 0.2032)
		(layers "F.Cu" "B.Cu")
		(net "GND")
	)
	(via
		(at 415.402014 -307.816758)
		(size 0.4572)
		(drill 0.2032)
		(layers "F.Cu" "B.Cu")
		(net "GND")
	)
	(via
		(at 309.992014 -214.316564)
		(size 0.4572)
		(drill 0.2032)
		(layers "F.Cu" "B.Cu")
		(net "GND")
	)
	(via
		(at 380.365762 -266.941808)
		(size 0.4572)
		(drill 0.2032)
		(layers "F.Cu" "B.Cu")
		(net "GND")
	)
	(via
		(at 257.185414 -263.616694)
		(size 0.4572)
		(drill 0.2032)
		(layers "F.Cu" "B.Cu")
		(net "GND")
	)
	(via
		(at 201.737214 -213.46668)
		(size 0.4572)
		(drill 0.2032)
		(layers "F.Cu" "B.Cu")
		(net "GND")
	)
	(via
		(at 407.858214 -220.266768)
		(size 0.4572)
		(drill 0.2032)
		(layers "F.Cu" "B.Cu")
		(net "GND")
	)
	(via
		(at 455.011282 -284.866588)
		(size 0.4572)
		(drill 0.2032)
		(layers "F.Cu" "B.Cu")
		(net "GND")
	)
	(via
		(at 307.782214 -304.416714)
		(size 0.4572)
		(drill 0.2032)
		(layers "F.Cu" "B.Cu")
		(net "GND")
	)
	(via
		(at 68.31076 -55.367428)
		(size 0.508)
		(drill 0.254)
		(layers "F.Cu" "B.Cu")
		(net "GND")
	)
	(via
		(at 48.767238 -410.030168)
		(size 0.4064)
		(drill 0.2032)
		(layers "F.Cu" "B.Cu")
		(net "GND")
	)
	(via
		(at 367.38052 -425.777914)
		(size 0.508)
		(drill 0.254)
		(layers "F.Cu" "B.Cu")
		(net "GND")
	)
	(via
		(at 412.66745 -400.858228)
		(size 0.4064)
		(drill 0.2032)
		(layers "F.Cu" "B.Cu")
		(net "GND")
	)
	(via
		(at 87.243158 -400.858228)
		(size 0.4064)
		(drill 0.2032)
		(layers "F.Cu" "B.Cu")
		(net "GND")
	)
	(via
		(at 350.841056 -244.753384)
		(size 0.4572)
		(drill 0.2032)
		(layers "F.Cu" "B.Cu")
		(net "GND")
	)
	(via
		(at 450.911214 -313.766708)
		(size 0.4572)
		(drill 0.2032)
		(layers "F.Cu" "B.Cu")
		(net "GND")
	)
	(via
		(at 448.896486 -73.912476)
		(size 0.508)
		(drill 0.254)
		(layers "F.Cu" "B.Cu")
		(net "GND")
	)
	(via
		(at 357.717344 -331.043026)
		(size 0.508)
		(drill 0.254)
		(layers "F.Cu" "B.Cu")
		(net "GND")
	)
	(via
		(at 85.43544 -275.08073)
		(size 0.4572)
		(drill 0.2032)
		(layers "F.Cu" "B.Cu")
		(net "GND")
	)
	(via
		(at 372.26748 -249.620024)
		(size 0.4572)
		(drill 0.2032)
		(layers "F.Cu" "B.Cu")
		(net "GND")
	)
	(via
		(at 289.250882 -289.966654)
		(size 0.4572)
		(drill 0.2032)
		(layers "F.Cu" "B.Cu")
		(net "GND")
	)
	(via
		(at 182.549546 -290.816792)
		(size 0.4572)
		(drill 0.2032)
		(layers "F.Cu" "B.Cu")
		(net "GND")
	)
	(via
		(at 348.412816 -279.964134)
		(size 0.4572)
		(drill 0.2032)
		(layers "F.Cu" "B.Cu")
		(net "GND")
	)
	(via
		(at 63.373 -7.203948)
		(size 0.508)
		(drill 0.254)
		(layers "F.Cu" "B.Cu")
		(net "GND")
	)
	(via
		(at 345.123516 -272.639282)
		(size 0.4572)
		(drill 0.2032)
		(layers "F.Cu" "B.Cu")
		(net "GND")
	)
	(via
		(at 31.386018 -6.597396)
		(size 0.508)
		(drill 0.254)
		(layers "F.Cu" "B.Cu")
		(net "GND")
	)
	(via
		(at 51.064414 -303.566576)
		(size 0.4572)
		(drill 0.2032)
		(layers "F.Cu" "B.Cu")
		(net "GND")
	)
	(via
		(at 52.298346 -265.316716)
		(size 0.4572)
		(drill 0.2032)
		(layers "F.Cu" "B.Cu")
		(net "GND")
	)
	(via
		(at 165.252146 -212.616796)
		(size 0.4572)
		(drill 0.2032)
		(layers "F.Cu" "B.Cu")
		(net "GND")
	)
	(via
		(at 287.360614 -270.416782)
		(size 0.4572)
		(drill 0.2032)
		(layers "F.Cu" "B.Cu")
		(net "GND")
	)
	(via
		(at 11.135614 -312.91657)
		(size 0.4572)
		(drill 0.2032)
		(layers "F.Cu" "B.Cu")
		(net "GND")
	)
	(via
		(at 393.046966 -12.37488)
		(size 0.508)
		(drill 0.254)
		(layers "F.Cu" "B.Cu")
		(net "GND")
	)
	(via
		(at 181.68112 -352.404172)
		(size 0.49022)
		(drill 0.254)
		(layers "F.Cu" "B.Cu")
		(net "GND")
	)
	(via
		(at 413.192214 -290.816792)
		(size 0.4572)
		(drill 0.2032)
		(layers "F.Cu" "B.Cu")
		(net "GND")
	)
	(via
		(at 340.784434 -239.0394)
		(size 0.4572)
		(drill 0.2032)
		(layers "F.Cu" "B.Cu")
		(net "GND")
	)
	(via
		(at 110.340394 -285.661354)
		(size 0.4572)
		(drill 0.2032)
		(layers "F.Cu" "B.Cu")
		(net "GND")
	)
	(via
		(at 262.519414 -307.816758)
		(size 0.4572)
		(drill 0.2032)
		(layers "F.Cu" "B.Cu")
		(net "GND")
	)
	(via
		(at 349.673164 -356.305612)
		(size 0.508)
		(drill 0.254)
		(layers "F.Cu" "B.Cu")
		(net "GND")
	)
	(via
		(at 414.110678 -404.51786)
		(size 0.4572)
		(drill 0.254)
		(layers "F.Cu" "B.Cu")
		(net "GND")
	)
	(via
		(at 164.018214 -250.866656)
		(size 0.4572)
		(drill 0.2032)
		(layers "F.Cu" "B.Cu")
		(net "GND")
	)
	(via
		(at 216.254584 -93.881956)
		(size 0.508)
		(drill 0.254)
		(layers "F.Cu" "B.Cu")
		(net "GND")
	)
	(via
		(at 384.124962 -263.686544)
		(size 0.4572)
		(drill 0.2032)
		(layers "F.Cu" "B.Cu")
		(net "GND")
	)
	(via
		(at 151.349964 -435.0512)
		(size 0.4572)
		(drill 0.2032)
		(layers "F.Cu" "B.Cu")
		(net "GND")
	)
	(via
		(at 331.484224 -338.964016)
		(size 0.508)
		(drill 0.254)
		(layers "F.Cu" "B.Cu")
		(net "GND")
	)
	(via
		(at 389.444738 -72.218296)
		(size 0.6604)
		(drill 0.3302)
		(layers "F.Cu" "B.Cu")
		(net "GND")
	)
	(via
		(at 129.606548 -257.175254)
		(size 0.4572)
		(drill 0.2032)
		(layers "F.Cu" "B.Cu")
		(net "GND")
	)
	(via
		(at 343.243662 -257.98907)
		(size 0.4572)
		(drill 0.2032)
		(layers "F.Cu" "B.Cu")
		(net "GND")
	)
	(via
		(at 57.572656 -161.572702)
		(size 0.508)
		(drill 0.254)
		(layers "F.Cu" "B.Cu")
		(net "GND")
	)
	(via
		(at 353.188524 -246.669306)
		(size 0.4572)
		(drill 0.2032)
		(layers "F.Cu" "B.Cu")
		(net "GND")
	)
	(via
		(at 339.84438 -247.178322)
		(size 0.4572)
		(drill 0.2032)
		(layers "F.Cu" "B.Cu")
		(net "GND")
	)
	(via
		(at 401.349972 -426.54728)
		(size 0.4572)
		(drill 0.2032)
		(layers "F.Cu" "B.Cu")
		(net "GND")
	)
	(via
		(at 51.998118 -19.770344)
		(size 0.508)
		(drill 0.254)
		(layers "F.Cu" "B.Cu")
		(net "GND")
	)
	(via
		(at 18.679414 -314.616592)
		(size 0.4572)
		(drill 0.2032)
		(layers "F.Cu" "B.Cu")
		(net "GND")
	)
	(via
		(at 46.964346 -300.166786)
		(size 0.4572)
		(drill 0.2032)
		(layers "F.Cu" "B.Cu")
		(net "GND")
	)
	(via
		(at 400.41449 -400.858228)
		(size 0.4064)
		(drill 0.2032)
		(layers "F.Cu" "B.Cu")
		(net "GND")
	)
	(via
		(at 124.437648 -254.733552)
		(size 0.4572)
		(drill 0.2032)
		(layers "F.Cu" "B.Cu")
		(net "GND")
	)
	(via
		(at 363.363256 -241.665252)
		(size 0.4572)
		(drill 0.2032)
		(layers "F.Cu" "B.Cu")
		(net "GND")
	)
	(via
		(at 367.568734 -220.319854)
		(size 0.4572)
		(drill 0.2032)
		(layers "F.Cu" "B.Cu")
		(net "GND")
	)
	(via
		(at 450.911214 -273.816572)
		(size 0.4572)
		(drill 0.2032)
		(layers "F.Cu" "B.Cu")
		(net "GND")
	)
	(via
		(at 442.133482 -316.316614)
		(size 0.4572)
		(drill 0.2032)
		(layers "F.Cu" "B.Cu")
		(net "GND")
	)
	(via
		(at 122.616468 -366.093248)
		(size 0.508)
		(drill 0.254)
		(layers "F.Cu" "B.Cu")
		(net "GND")
	)
	(via
		(at 134.305294 -278.336502)
		(size 0.4572)
		(drill 0.2032)
		(layers "F.Cu" "B.Cu")
		(net "GND")
	)
	(via
		(at 77.47635 -36.627308)
		(size 0.508)
		(drill 0.254)
		(layers "F.Cu" "B.Cu")
		(net "GND")
	)
	(via
		(at 134.775194 -284.033722)
		(size 0.4572)
		(drill 0.2032)
		(layers "F.Cu" "B.Cu")
		(net "GND")
	)
	(via
		(at 344.543634 -216.25052)
		(size 0.4572)
		(drill 0.2032)
		(layers "F.Cu" "B.Cu")
		(net "GND")
	)
	(via
		(at 431.68443 -362.170472)
		(size 0.508)
		(drill 0.254)
		(layers "F.Cu" "B.Cu")
		(net "GND")
	)
	(via
		(at 296.794682 -310.366664)
		(size 0.4572)
		(drill 0.2032)
		(layers "F.Cu" "B.Cu")
		(net "GND")
	)
	(via
		(at 129.606294 -283.219906)
		(size 0.4572)
		(drill 0.2032)
		(layers "F.Cu" "B.Cu")
		(net "GND")
	)
	(via
		(at 80.645254 -341.766906)
		(size 0.49022)
		(drill 0.254)
		(layers "F.Cu" "B.Cu")
		(net "GND")
	)
	(via
		(at 45.890688 -351.888298)
		(size 0.508)
		(drill 0.254)
		(layers "F.Cu" "B.Cu")
		(net "GND")
	)
	(via
		(at 46.964346 -309.51678)
		(size 0.4572)
		(drill 0.2032)
		(layers "F.Cu" "B.Cu")
		(net "GND")
	)
	(via
		(at 384.485134 -217.064336)
		(size 0.4572)
		(drill 0.2032)
		(layers "F.Cu" "B.Cu")
		(net "GND")
	)
	(via
		(at 166.447978 -418.448744)
		(size 0.508)
		(drill 0.254)
		(layers "F.Cu" "B.Cu")
		(net "GND")
	)
	(via
		(at 78.414626 -403.249892)
		(size 0.4572)
		(drill 0.254)
		(layers "F.Cu" "B.Cu")
		(net "GND")
	)
	(via
		(at 226.900994 -123.324874)
		(size 0.508)
		(drill 0.254)
		(layers "F.Cu" "B.Cu")
		(net "GND")
	)
	(via
		(at 145.349976 -428.851314)
		(size 0.4572)
		(drill 0.2032)
		(layers "F.Cu" "B.Cu")
		(net "GND")
	)
	(via
		(at 460.664814 -214.316564)
		(size 0.4572)
		(drill 0.2032)
		(layers "F.Cu" "B.Cu")
		(net "GND")
	)
	(via
		(at 398.96288 -185.257948)
		(size 0.508)
		(drill 0.254)
		(layers "F.Cu" "B.Cu")
		(net "GND")
	)
	(via
		(at 337.604862 -256.361438)
		(size 0.4572)
		(drill 0.2032)
		(layers "F.Cu" "B.Cu")
		(net "GND")
	)
	(via
		(at 52.298346 -242.3668)
		(size 0.4572)
		(drill 0.2032)
		(layers "F.Cu" "B.Cu")
		(net "GND")
	)
	(via
		(at 375.55678 -245.55069)
		(size 0.4572)
		(drill 0.2032)
		(layers "F.Cu" "B.Cu")
		(net "GND")
	)
	(via
		(at 171.666916 -12.495022)
		(size 0.508)
		(drill 0.254)
		(layers "F.Cu" "B.Cu")
		(net "GND")
	)
	(via
		(at 346.532962 -286.475424)
		(size 0.4572)
		(drill 0.2032)
		(layers "F.Cu" "B.Cu")
		(net "GND")
	)
	(via
		(at 211.149438 -26.468324)
		(size 0.508)
		(drill 0.254)
		(layers "F.Cu" "B.Cu")
		(net "GND")
	)
	(via
		(at 124.366782 -407.638504)
		(size 0.4572)
		(drill 0.254)
		(layers "F.Cu" "B.Cu")
		(net "GND")
	)
	(via
		(at 51.064414 -200.716642)
		(size 0.4572)
		(drill 0.2032)
		(layers "F.Cu" "B.Cu")
		(net "GND")
	)
	(via
		(at 458.455014 -281.466798)
		(size 0.4572)
		(drill 0.2032)
		(layers "F.Cu" "B.Cu")
		(net "GND")
	)
	(via
		(at 74.39533 -441.225432)
		(size 0.508)
		(drill 0.254)
		(layers "F.Cu" "B.Cu")
		(net "GND")
	)
	(via
		(at 366.738662 -284.033722)
		(size 0.4572)
		(drill 0.2032)
		(layers "F.Cu" "B.Cu")
		(net "GND")
	)
	(via
		(at 214.615014 -213.46668)
		(size 0.4572)
		(drill 0.2032)
		(layers "F.Cu" "B.Cu")
		(net "GND")
	)
	(via
		(at 126.350014 -427.851316)
		(size 0.4572)
		(drill 0.2032)
		(layers "F.Cu" "B.Cu")
		(net "GND")
	)
	(via
		(at 61.655198 -403.883876)
		(size 0.4064)
		(drill 0.2032)
		(layers "F.Cu" "B.Cu")
		(net "GND")
	)
	(via
		(at 92.844366 -243.922804)
		(size 0.4572)
		(drill 0.2032)
		(layers "F.Cu" "B.Cu")
		(net "GND")
	)
	(via
		(at 424.836082 -213.46668)
		(size 0.4572)
		(drill 0.2032)
		(layers "F.Cu" "B.Cu")
		(net "GND")
	)
	(via
		(at 412.84398 -175.707548)
		(size 0.508)
		(drill 0.254)
		(layers "F.Cu" "B.Cu")
		(net "GND")
	)
	(via
		(at 108.351066 -217.064336)
		(size 0.4572)
		(drill 0.2032)
		(layers "F.Cu" "B.Cu")
		(net "GND")
	)
	(via
		(at 407.858214 -201.56678)
		(size 0.4572)
		(drill 0.2032)
		(layers "F.Cu" "B.Cu")
		(net "GND")
	)
	(via
		(at 87.604346 -401.492212)
		(size 0.4572)
		(drill 0.254)
		(layers "F.Cu" "B.Cu")
		(net "GND")
	)
	(via
		(at 365.54537 -355.362256)
		(size 0.508)
		(drill 0.254)
		(layers "F.Cu" "B.Cu")
		(net "GND")
	)
	(via
		(at 438.033414 -272.116804)
		(size 0.4572)
		(drill 0.2032)
		(layers "F.Cu" "B.Cu")
		(net "GND")
	)
	(via
		(at 41.310814 -305.266598)
		(size 0.4572)
		(drill 0.2032)
		(layers "F.Cu" "B.Cu")
		(net "GND")
	)
	(via
		(at 303.4665 -361.866688)
		(size 0.508)
		(drill 0.254)
		(layers "F.Cu" "B.Cu")
		(net "GND")
	)
	(via
		(at 13.345414 -230.466646)
		(size 0.4572)
		(drill 0.2032)
		(layers "F.Cu" "B.Cu")
		(net "GND")
	)
	(via
		(at 353.252532 -338.702142)
		(size 0.508)
		(drill 0.254)
		(layers "F.Cu" "B.Cu")
		(net "GND")
	)
	(via
		(at 9.245346 -261.916672)
		(size 0.4572)
		(drill 0.2032)
		(layers "F.Cu" "B.Cu")
		(net "GND")
	)
	(via
		(at 424.836082 -239.81664)
		(size 0.4572)
		(drill 0.2032)
		(layers "F.Cu" "B.Cu")
		(net "GND")
	)
	(via
		(at 239.1156 -205.755748)
		(size 0.508)
		(drill 0.254)
		(layers "F.Cu" "B.Cu")
		(net "GND")
	)
	(via
		(at 435.823614 -199.01662)
		(size 0.4572)
		(drill 0.2032)
		(layers "F.Cu" "B.Cu")
		(net "GND")
	)
	(via
		(at 139.60094 -30.653228)
		(size 0.508)
		(drill 0.254)
		(layers "F.Cu" "B.Cu")
		(net "GND")
	)
	(via
		(at 44.754546 -208.366614)
		(size 0.4572)
		(drill 0.2032)
		(layers "F.Cu" "B.Cu")
		(net "GND")
	)
	(via
		(at 182.13324 -345.64701)
		(size 0.508)
		(drill 0.254)
		(layers "F.Cu" "B.Cu")
		(net "GND")
	)
	(via
		(at 202.971146 -220.266768)
		(size 0.4572)
		(drill 0.2032)
		(layers "F.Cu" "B.Cu")
		(net "GND")
	)
	(via
		(at 29.91993 -431.510948)
		(size 0.508)
		(drill 0.254)
		(layers "F.Cu" "B.Cu")
		(net "GND")
	)
	(via
		(at 35.976814 -275.516594)
		(size 0.4572)
		(drill 0.2032)
		(layers "F.Cu" "B.Cu")
		(net "GND")
	)
	(via
		(at 289.250882 -219.41663)
		(size 0.4572)
		(drill 0.2032)
		(layers "F.Cu" "B.Cu")
		(net "GND")
	)
	(via
		(at 205.180946 -203.266802)
		(size 0.4572)
		(drill 0.2032)
		(layers "F.Cu" "B.Cu")
		(net "GND")
	)
	(via
		(at 167.252142 -407.638504)
		(size 0.4572)
		(drill 0.254)
		(layers "F.Cu" "B.Cu")
		(net "GND")
	)
	(via
		(at 420.736014 -307.816758)
		(size 0.4572)
		(drill 0.2032)
		(layers "F.Cu" "B.Cu")
		(net "GND")
	)
	(via
		(at 133.255512 -247.178322)
		(size 0.4572)
		(drill 0.2032)
		(layers "F.Cu" "B.Cu")
		(net "GND")
	)
	(via
		(at 335.953608 -40.931846)
		(size 0.4572)
		(drill 0.2032)
		(layers "F.Cu" "B.Cu")
		(net "GND")
	)
	(via
		(at 394.349986 -426.69968)
		(size 0.4572)
		(drill 0.2032)
		(layers "F.Cu" "B.Cu")
		(net "GND")
	)
	(via
		(at 372.477792 -361.060746)
		(size 0.508)
		(drill 0.254)
		(layers "F.Cu" "B.Cu")
		(net "GND")
	)
	(via
		(at 91.544648 -287.28924)
		(size 0.4572)
		(drill 0.2032)
		(layers "F.Cu" "B.Cu")
		(net "GND")
	)
	(via
		(at 283.916882 -308.666642)
		(size 0.4572)
		(drill 0.2032)
		(layers "F.Cu" "B.Cu")
		(net "GND")
	)
	(via
		(at 306.845716 -404.51786)
		(size 0.4572)
		(drill 0.254)
		(layers "F.Cu" "B.Cu")
		(net "GND")
	)
	(via
		(at 426.320204 -354.180394)
		(size 0.508)
		(drill 0.254)
		(layers "F.Cu" "B.Cu")
		(net "GND")
	)
	(via
		(at 52.298346 -283.166566)
		(size 0.4572)
		(drill 0.2032)
		(layers "F.Cu" "B.Cu")
		(net "GND")
	)
	(via
		(at 345.15171 -44.349162)
		(size 0.4572)
		(drill 0.2032)
		(layers "F.Cu" "B.Cu")
		(net "GND")
	)
	(via
		(at 112.579912 -216.25052)
		(size 0.4572)
		(drill 0.2032)
		(layers "F.Cu" "B.Cu")
		(net "GND")
	)
	(via
		(at 54.508146 -238.966756)
		(size 0.4572)
		(drill 0.2032)
		(layers "F.Cu" "B.Cu")
		(net "GND")
	)
	(via
		(at 318.410844 -339.000846)
		(size 0.508)
		(drill 0.254)
		(layers "F.Cu" "B.Cu")
		(net "GND")
	)
	(via
		(at 378.016516 -277.522432)
		(size 0.4572)
		(drill 0.2032)
		(layers "F.Cu" "B.Cu")
		(net "GND")
	)
	(via
		(at 257.185414 -233.016806)
		(size 0.4572)
		(drill 0.2032)
		(layers "F.Cu" "B.Cu")
		(net "GND")
	)
	(via
		(at 291.460682 -216.866724)
		(size 0.4572)
		(drill 0.2032)
		(layers "F.Cu" "B.Cu")
		(net "GND")
	)
	(via
		(at 366.72139 -339.339174)
		(size 0.508)
		(drill 0.254)
		(layers "F.Cu" "B.Cu")
		(net "GND")
	)
	(via
		(at 56.83885 -147.150074)
		(size 0.49022)
		(drill 0.254)
		(layers "F.Cu" "B.Cu")
		(net "GND")
	)
	(via
		(at 20.889214 -230.466646)
		(size 0.4572)
		(drill 0.2032)
		(layers "F.Cu" "B.Cu")
		(net "GND")
	)
	(via
		(at 332.250034 -438.651396)
		(size 0.4572)
		(drill 0.2032)
		(layers "F.Cu" "B.Cu")
		(net "GND")
	)
	(via
		(at 344.183462 -256.361438)
		(size 0.4572)
		(drill 0.2032)
		(layers "F.Cu" "B.Cu")
		(net "GND")
	)
	(via
		(at 161.808414 -316.316614)
		(size 0.4572)
		(drill 0.2032)
		(layers "F.Cu" "B.Cu")
		(net "GND")
	)
	(via
		(at 403.203918 -406.370536)
		(size 0.4572)
		(drill 0.254)
		(layers "F.Cu" "B.Cu")
		(net "GND")
	)
	(via
		(at 126.350014 -426.69968)
		(size 0.4572)
		(drill 0.2032)
		(layers "F.Cu" "B.Cu")
		(net "GND")
	)
	(via
		(at 26.223214 -241.516662)
		(size 0.4572)
		(drill 0.2032)
		(layers "F.Cu" "B.Cu")
		(net "GND")
	)
	(via
		(at 43.520614 -266.1666)
		(size 0.4572)
		(drill 0.2032)
		(layers "F.Cu" "B.Cu")
		(net "GND")
	)
	(via
		(at 105.763822 -239.292892)
		(size 0.4572)
		(drill 0.2032)
		(layers "F.Cu" "B.Cu")
		(net "GND")
	)
	(via
		(at 398.446752 -7.215124)
		(size 0.508)
		(drill 0.254)
		(layers "F.Cu" "B.Cu")
		(net "GND")
	)
	(via
		(at 118.328694 -265.314176)
		(size 0.4572)
		(drill 0.2032)
		(layers "F.Cu" "B.Cu")
		(net "GND")
	)
	(via
		(at 161.808414 -250.866656)
		(size 0.4572)
		(drill 0.2032)
		(layers "F.Cu" "B.Cu")
		(net "GND")
	)
	(via
		(at 399.992596 -19.125438)
		(size 0.508)
		(drill 0.254)
		(layers "F.Cu" "B.Cu")
		(net "GND")
	)
	(via
		(at 432.379882 -210.066636)
		(size 0.4572)
		(drill 0.2032)
		(layers "F.Cu" "B.Cu")
		(net "GND")
	)
	(via
		(at 125.377448 -257.98907)
		(size 0.4572)
		(drill 0.2032)
		(layers "F.Cu" "B.Cu")
		(net "GND")
	)
	(via
		(at 197.637146 -265.316716)
		(size 0.4572)
		(drill 0.2032)
		(layers "F.Cu" "B.Cu")
		(net "GND")
	)
	(via
		(at 191.983614 -286.56661)
		(size 0.4572)
		(drill 0.2032)
		(layers "F.Cu" "B.Cu")
		(net "GND")
	)
	(via
		(at 380.256034 -239.0394)
		(size 0.4572)
		(drill 0.2032)
		(layers "F.Cu" "B.Cu")
		(net "GND")
	)
	(via
		(at 137.975594 -403.883876)
		(size 0.4064)
		(drill 0.2032)
		(layers "F.Cu" "B.Cu")
		(net "GND")
	)
	(via
		(at 277.607014 -199.01662)
		(size 0.4572)
		(drill 0.2032)
		(layers "F.Cu" "B.Cu")
		(net "GND")
	)
	(via
		(at 358.280462 -259.616956)
		(size 0.4572)
		(drill 0.2032)
		(layers "F.Cu" "B.Cu")
		(net "GND")
	)
	(via
		(at 119.957342 -400.224244)
		(size 0.4572)
		(drill 0.254)
		(layers "F.Cu" "B.Cu")
		(net "GND")
	)
	(via
		(at 20.889214 -272.966688)
		(size 0.4572)
		(drill 0.2032)
		(layers "F.Cu" "B.Cu")
		(net "GND")
	)
	(via
		(at 56.398414 -303.566576)
		(size 0.4572)
		(drill 0.2032)
		(layers "F.Cu" "B.Cu")
		(net "GND")
	)
	(via
		(at 93.730826 -403.249892)
		(size 0.4572)
		(drill 0.254)
		(layers "F.Cu" "B.Cu")
		(net "GND")
	)
	(via
		(at 382.19888 -337.602322)
		(size 0.508)
		(drill 0.254)
		(layers "F.Cu" "B.Cu")
		(net "GND")
	)
	(via
		(at 151.349964 -433.899564)
		(size 0.4572)
		(drill 0.2032)
		(layers "F.Cu" "B.Cu")
		(net "GND")
	)
	(via
		(at 435.823614 -204.96657)
		(size 0.4572)
		(drill 0.2032)
		(layers "F.Cu" "B.Cu")
		(net "GND")
	)
	(via
		(at 16.789146 -229.616762)
		(size 0.4572)
		(drill 0.2032)
		(layers "F.Cu" "B.Cu")
		(net "GND")
	)
	(via
		(at 341.834216 -270.19758)
		(size 0.4572)
		(drill 0.2032)
		(layers "F.Cu" "B.Cu")
		(net "GND")
	)
	(via
		(at 292.694614 -290.816792)
		(size 0.4572)
		(drill 0.2032)
		(layers "F.Cu" "B.Cu")
		(net "GND")
	)
	(via
		(at 92.954348 -255.547622)
		(size 0.4572)
		(drill 0.2032)
		(layers "F.Cu" "B.Cu")
		(net "GND")
	)
	(via
		(at 52.298346 -268.71676)
		(size 0.4572)
		(drill 0.2032)
		(layers "F.Cu" "B.Cu")
		(net "GND")
	)
	(via
		(at 108.43387 -249.005344)
		(size 0.4572)
		(drill 0.2032)
		(layers "F.Cu" "B.Cu")
		(net "GND")
	)
	(via
		(at 176.901348 -350.093788)
		(size 0.508)
		(drill 0.254)
		(layers "F.Cu" "B.Cu")
		(net "GND")
	)
	(via
		(at 366.738916 -277.522432)
		(size 0.4572)
		(drill 0.2032)
		(layers "F.Cu" "B.Cu")
		(net "GND")
	)
	(via
		(at 346.532962 -270.19758)
		(size 0.4572)
		(drill 0.2032)
		(layers "F.Cu" "B.Cu")
		(net "GND")
	)
	(via
		(at 368.618262 -280.778204)
		(size 0.4572)
		(drill 0.2032)
		(layers "F.Cu" "B.Cu")
		(net "GND")
	)
	(via
		(at 115.95608 -123.148598)
		(size 0.508)
		(drill 0.254)
		(layers "F.Cu" "B.Cu")
		(net "GND")
	)
	(via
		(at 210.7692 -68.976748)
		(size 0.508)
		(drill 0.254)
		(layers "F.Cu" "B.Cu")
		(net "GND")
	)
	(via
		(at 294.904414 -227.066602)
		(size 0.4572)
		(drill 0.2032)
		(layers "F.Cu" "B.Cu")
		(net "GND")
	)
	(via
		(at 120.568212 -228.45903)
		(size 0.4572)
		(drill 0.2032)
		(layers "F.Cu" "B.Cu")
		(net "GND")
	)
	(via
		(at 176.896014 -261.066788)
		(size 0.4572)
		(drill 0.2032)
		(layers "F.Cu" "B.Cu")
		(net "GND")
	)
	(via
		(at 11.135614 -250.866656)
		(size 0.4572)
		(drill 0.2032)
		(layers "F.Cu" "B.Cu")
		(net "GND")
	)
	(via
		(at 405.648414 -292.516814)
		(size 0.4572)
		(drill 0.2032)
		(layers "F.Cu" "B.Cu")
		(net "GND")
	)
	(via
		(at 7.035546 -298.466764)
		(size 0.4572)
		(drill 0.2032)
		(layers "F.Cu" "B.Cu")
		(net "GND")
	)
	(via
		(at 205.6638 -69.484748)
		(size 0.508)
		(drill 0.254)
		(layers "F.Cu" "B.Cu")
		(net "GND")
	)
	(via
		(at 424.936412 -18.235422)
		(size 0.508)
		(drill 0.254)
		(layers "F.Cu" "B.Cu")
		(net "GND")
	)
	(via
		(at 342.250014 -433.747164)
		(size 0.4572)
		(drill 0.2032)
		(layers "F.Cu" "B.Cu")
		(net "GND")
	)
	(via
		(at 300.238414 -307.816758)
		(size 0.4572)
		(drill 0.2032)
		(layers "F.Cu" "B.Cu")
		(net "GND")
	)
	(via
		(at 133.835394 -279.150318)
		(size 0.4572)
		(drill 0.2032)
		(layers "F.Cu" "B.Cu")
		(net "GND")
	)
	(via
		(at 277.607014 -229.616762)
		(size 0.4572)
		(drill 0.2032)
		(layers "F.Cu" "B.Cu")
		(net "GND")
	)
	(via
		(at 151.349964 -427.851316)
		(size 0.4572)
		(drill 0.2032)
		(layers "F.Cu" "B.Cu")
		(net "GND")
	)
	(via
		(at 273.966686 -12.544552)
		(size 0.508)
		(drill 0.254)
		(layers "F.Cu" "B.Cu")
		(net "GND")
	)
	(via
		(at 11.135614 -224.516696)
		(size 0.4572)
		(drill 0.2032)
		(layers "F.Cu" "B.Cu")
		(net "GND")
	)
	(via
		(at 134.349998 -432.747166)
		(size 0.4572)
		(drill 0.2032)
		(layers "F.Cu" "B.Cu")
		(net "GND")
	)
	(via
		(at 206.9592 -193.274188)
		(size 0.508)
		(drill 0.254)
		(layers "F.Cu" "B.Cu")
		(net "GND")
	)
	(via
		(at 108.43387 -245.34749)
		(size 0.4572)
		(drill 0.2032)
		(layers "F.Cu" "B.Cu")
		(net "GND")
	)
	(via
		(at 349.242634 -226.017328)
		(size 0.4572)
		(drill 0.2032)
		(layers "F.Cu" "B.Cu")
		(net "GND")
	)
	(via
		(at 171.50588 -131.280408)
		(size 0.508)
		(drill 0.254)
		(layers "F.Cu" "B.Cu")
		(net "GND")
	)
	(via
		(at 296.97299 -363.337094)
		(size 0.49022)
		(drill 0.254)
		(layers "F.Cu" "B.Cu")
		(net "GND")
	)
	(via
		(at 194.193414 -249.166634)
		(size 0.4572)
		(drill 0.2032)
		(layers "F.Cu" "B.Cu")
		(net "GND")
	)
	(via
		(at 346.423234 -216.25052)
		(size 0.4572)
		(drill 0.2032)
		(layers "F.Cu" "B.Cu")
		(net "GND")
	)
	(via
		(at 349.242634 -216.25052)
		(size 0.4572)
		(drill 0.2032)
		(layers "F.Cu" "B.Cu")
		(net "GND")
	)
	(via
		(at 279.816814 -238.966756)
		(size 0.4572)
		(drill 0.2032)
		(layers "F.Cu" "B.Cu")
		(net "GND")
	)
	(via
		(at 325.98995 -45.535088)
		(size 0.508)
		(drill 0.254)
		(layers "F.Cu" "B.Cu")
		(net "GND")
	)
	(via
		(at 99.865434 -330.42352)
		(size 0.508)
		(drill 0.254)
		(layers "F.Cu" "B.Cu")
		(net "GND")
	)
	(via
		(at 314.318396 -409.396184)
		(size 0.4572)
		(drill 0.254)
		(layers "F.Cu" "B.Cu")
		(net "GND")
	)
	(via
		(at 121.85396 -76.251308)
		(size 0.508)
		(drill 0.254)
		(layers "F.Cu" "B.Cu")
		(net "GND")
	)
	(via
		(at 348.453964 -441.225432)
		(size 0.508)
		(drill 0.254)
		(layers "F.Cu" "B.Cu")
		(net "GND")
	)
	(via
		(at 405.648414 -246.616728)
		(size 0.4572)
		(drill 0.2032)
		(layers "F.Cu" "B.Cu")
		(net "GND")
	)
	(via
		(at 346.063316 -264.50036)
		(size 0.4572)
		(drill 0.2032)
		(layers "F.Cu" "B.Cu")
		(net "GND")
	)
	(via
		(at 62.051946 -267.016738)
		(size 0.4572)
		(drill 0.2032)
		(layers "F.Cu" "B.Cu")
		(net "GND")
	)
	(via
		(at 63.942214 -200.716642)
		(size 0.4572)
		(drill 0.2032)
		(layers "F.Cu" "B.Cu")
		(net "GND")
	)
	(via
		(at 164.018214 -286.56661)
		(size 0.4572)
		(drill 0.2032)
		(layers "F.Cu" "B.Cu")
		(net "GND")
	)
	(via
		(at 340.305136 -334.494124)
		(size 0.508)
		(drill 0.254)
		(layers "F.Cu" "B.Cu")
		(net "GND")
	)
	(via
		(at 87.785194 -266.128246)
		(size 0.4572)
		(drill 0.2032)
		(layers "F.Cu" "B.Cu")
		(net "GND")
	)
	(via
		(at 91.074494 -286.475424)
		(size 0.4572)
		(drill 0.2032)
		(layers "F.Cu" "B.Cu")
		(net "GND")
	)
	(via
		(at 212.724746 -227.066602)
		(size 0.4572)
		(drill 0.2032)
		(layers "F.Cu" "B.Cu")
		(net "GND")
	)
	(via
		(at 234.15752 -387.37794)
		(size 0.508)
		(drill 0.254)
		(layers "F.Cu" "B.Cu")
		(net "GND")
	)
	(via
		(at 262.519414 -248.31675)
		(size 0.4572)
		(drill 0.2032)
		(layers "F.Cu" "B.Cu")
		(net "GND")
	)
	(via
		(at 35.216084 -323.434456)
		(size 0.4572)
		(drill 0.2032)
		(layers "F.Cu" "B.Cu")
		(net "GND")
	)
	(via
		(at 175.005746 -289.11677)
		(size 0.4572)
		(drill 0.2032)
		(layers "F.Cu" "B.Cu")
		(net "GND")
	)
	(via
		(at 266.7508 -151.907748)
		(size 0.508)
		(drill 0.254)
		(layers "F.Cu" "B.Cu")
		(net "GND")
	)
	(via
		(at 457.221082 -291.666676)
		(size 0.4572)
		(drill 0.2032)
		(layers "F.Cu" "B.Cu")
		(net "GND")
	)
	(via
		(at 155.349956 -432.747166)
		(size 0.4572)
		(drill 0.2032)
		(layers "F.Cu" "B.Cu")
		(net "GND")
	)
	(via
		(at 140.349986 -431.29962)
		(size 0.4572)
		(drill 0.2032)
		(layers "F.Cu" "B.Cu")
		(net "GND")
	)
	(via
		(at 86.735412 -230.086662)
		(size 0.4318)
		(drill 0.2032)
		(layers "F.Cu" "B.Cu")
		(net "GND")
	)
	(via
		(at 28.433014 -277.216616)
		(size 0.4572)
		(drill 0.2032)
		(layers "F.Cu" "B.Cu")
		(net "GND")
	)
	(via
		(at 134.305548 -253.919736)
		(size 0.4572)
		(drill 0.2032)
		(layers "F.Cu" "B.Cu")
		(net "GND")
	)
	(via
		(at 195.22948 -353.761548)
		(size 0.508)
		(drill 0.254)
		(layers "F.Cu" "B.Cu")
		(net "GND")
	)
	(via
		(at 359.580434 -227.64496)
		(size 0.4572)
		(drill 0.2032)
		(layers "F.Cu" "B.Cu")
		(net "GND")
	)
	(via
		(at 276.373082 -314.616592)
		(size 0.4572)
		(drill 0.2032)
		(layers "F.Cu" "B.Cu")
		(net "GND")
	)
	(via
		(at 419.502082 -269.566644)
		(size 0.4572)
		(drill 0.2032)
		(layers "F.Cu" "B.Cu")
		(net "GND")
	)
	(via
		(at 171.562014 -247.466612)
		(size 0.4572)
		(drill 0.2032)
		(layers "F.Cu" "B.Cu")
		(net "GND")
	)
	(via
		(at 373.317262 -279.150318)
		(size 0.4572)
		(drill 0.2032)
		(layers "F.Cu" "B.Cu")
		(net "GND")
	)
	(via
		(at 311.16778 -401.492212)
		(size 0.4572)
		(drill 0.254)
		(layers "F.Cu" "B.Cu")
		(net "GND")
	)
	(via
		(at 415.649918 -168.657778)
		(size 0.49022)
		(drill 0.254)
		(layers "F.Cu" "B.Cu")
		(net "GND")
	)
	(via
		(at 187.883546 -309.51678)
		(size 0.4572)
		(drill 0.2032)
		(layers "F.Cu" "B.Cu")
		(net "GND")
	)
	(via
		(at 10.01014 -97.683828)
		(size 0.508)
		(drill 0.254)
		(layers "F.Cu" "B.Cu")
		(net "GND")
	)
	(via
		(at 346.063316 -254.733552)
		(size 0.4572)
		(drill 0.2032)
		(layers "F.Cu" "B.Cu")
		(net "GND")
	)
	(via
		(at 18.679414 -262.76681)
		(size 0.4572)
		(drill 0.2032)
		(layers "F.Cu" "B.Cu")
		(net "GND")
	)
	(via
		(at 418.432742 -403.249892)
		(size 0.4572)
		(drill 0.254)
		(layers "F.Cu" "B.Cu")
		(net "GND")
	)
	(via
		(at 267.357352 -323.429376)
		(size 0.4572)
		(drill 0.2032)
		(layers "F.Cu" "B.Cu")
		(net "GND")
	)
	(via
		(at 36.642802 -358.71785)
		(size 0.508)
		(drill 0.254)
		(layers "F.Cu" "B.Cu")
		(net "GND")
	)
	(via
		(at 53.64988 -188.051948)
		(size 0.508)
		(drill 0.254)
		(layers "F.Cu" "B.Cu")
		(net "GND")
	)
	(via
		(at 58.608214 -310.366664)
		(size 0.4572)
		(drill 0.2032)
		(layers "F.Cu" "B.Cu")
		(net "GND")
	)
	(via
		(at 26.223214 -250.866656)
		(size 0.4572)
		(drill 0.2032)
		(layers "F.Cu" "B.Cu")
		(net "GND")
	)
	(via
		(at 434.630576 -108.19003)
		(size 0.508)
		(drill 0.254)
		(layers "F.Cu" "B.Cu")
		(net "GND")
	)
	(via
		(at 28.433014 -239.81664)
		(size 0.4572)
		(drill 0.2032)
		(layers "F.Cu" "B.Cu")
		(net "GND")
	)
	(via
		(at 20.115784 -4.962652)
		(size 0.508)
		(drill 0.254)
		(layers "F.Cu" "B.Cu")
		(net "GND")
	)
	(via
		(at 127.068834 -410.030168)
		(size 0.4064)
		(drill 0.2032)
		(layers "F.Cu" "B.Cu")
		(net "GND")
	)
	(via
		(at 175.005746 -246.616728)
		(size 0.4572)
		(drill 0.2032)
		(layers "F.Cu" "B.Cu")
		(net "GND")
	)
	(via
		(at 442.133482 -205.816708)
		(size 0.4572)
		(drill 0.2032)
		(layers "F.Cu" "B.Cu")
		(net "GND")
	)
	(via
		(at 178.425348 -425.007532)
		(size 0.508)
		(drill 0.254)
		(layers "F.Cu" "B.Cu")
		(net "GND")
	)
	(via
		(at 363.368336 -256.389632)
		(size 0.4572)
		(drill 0.2032)
		(layers "F.Cu" "B.Cu")
		(net "GND")
	)
	(via
		(at 106.59999 -331.776832)
		(size 0.49022)
		(drill 0.254)
		(layers "F.Cu" "B.Cu")
		(net "GND")
	)
	(via
		(at 124.437394 -287.28924)
		(size 0.4572)
		(drill 0.2032)
		(layers "F.Cu" "B.Cu")
		(net "GND")
	)
	(via
		(at 20.43684 -166.540688)
		(size 0.508)
		(drill 0.254)
		(layers "F.Cu" "B.Cu")
		(net "GND")
	)
	(via
		(at 169.352214 -271.266666)
		(size 0.4572)
		(drill 0.2032)
		(layers "F.Cu" "B.Cu")
		(net "GND")
	)
	(via
		(at 103.291894 -279.964134)
		(size 0.4572)
		(drill 0.2032)
		(layers "F.Cu" "B.Cu")
		(net "GND")
	)
	(via
		(at 11.135614 -267.866622)
		(size 0.4572)
		(drill 0.2032)
		(layers "F.Cu" "B.Cu")
		(net "GND")
	)
	(via
		(at 306.548282 -275.516594)
		(size 0.4572)
		(drill 0.2032)
		(layers "F.Cu" "B.Cu")
		(net "GND")
	)
	(via
		(at 442.133482 -295.916604)
		(size 0.4572)
		(drill 0.2032)
		(layers "F.Cu" "B.Cu")
		(net "GND")
	)
	(via
		(at 26.223214 -295.916604)
		(size 0.4572)
		(drill 0.2032)
		(layers "F.Cu" "B.Cu")
		(net "GND")
	)
	(via
		(at 195.427346 -204.96657)
		(size 0.4572)
		(drill 0.2032)
		(layers "F.Cu" "B.Cu")
		(net "GND")
	)
	(via
		(at 395.63421 -410.030168)
		(size 0.4064)
		(drill 0.2032)
		(layers "F.Cu" "B.Cu")
		(net "GND")
	)
	(via
		(at 172.795946 -220.266768)
		(size 0.4572)
		(drill 0.2032)
		(layers "F.Cu" "B.Cu")
		(net "GND")
	)
	(via
		(at 347.473016 -260.430772)
		(size 0.4572)
		(drill 0.2032)
		(layers "F.Cu" "B.Cu")
		(net "GND")
	)
	(via
		(at 464.764882 -269.566644)
		(size 0.4572)
		(drill 0.2032)
		(layers "F.Cu" "B.Cu")
		(net "GND")
	)
	(via
		(at 84.250022 -437.49976)
		(size 0.4572)
		(drill 0.2032)
		(layers "F.Cu" "B.Cu")
		(net "GND")
	)
	(via
		(at 465.917788 -12.544552)
		(size 0.508)
		(drill 0.254)
		(layers "F.Cu" "B.Cu")
		(net "GND")
	)
	(via
		(at 11.135614 -303.566576)
		(size 0.4572)
		(drill 0.2032)
		(layers "F.Cu" "B.Cu")
		(net "GND")
	)
	(via
		(at 134.305548 -262.058658)
		(size 0.4572)
		(drill 0.2032)
		(layers "F.Cu" "B.Cu")
		(net "GND")
	)
	(via
		(at 447.467482 -205.816708)
		(size 0.4572)
		(drill 0.2032)
		(layers "F.Cu" "B.Cu")
		(net "GND")
	)
	(via
		(at 422.221152 -323.429376)
		(size 0.4572)
		(drill 0.2032)
		(layers "F.Cu" "B.Cu")
		(net "GND")
	)
	(via
		(at 119.94134 -411.131004)
		(size 0.508)
		(drill 0.254)
		(layers "F.Cu" "B.Cu")
		(net "GND")
	)
	(via
		(at 212.724746 -223.666558)
		(size 0.4572)
		(drill 0.2032)
		(layers "F.Cu" "B.Cu")
		(net "GND")
	)
	(via
		(at 361.92968 -238.225584)
		(size 0.4572)
		(drill 0.2032)
		(layers "F.Cu" "B.Cu")
		(net "GND")
	)
	(via
		(at 376.23877 -351.038668)
		(size 0.508)
		(drill 0.254)
		(layers "F.Cu" "B.Cu")
		(net "GND")
	)
	(via
		(at 353.396804 -250.337066)
		(size 0.4572)
		(drill 0.2032)
		(layers "F.Cu" "B.Cu")
		(net "GND")
	)
	(via
		(at 382.135634 -245.55069)
		(size 0.4572)
		(drill 0.2032)
		(layers "F.Cu" "B.Cu")
		(net "GND")
	)
	(via
		(at 196.581522 -29.116782)
		(size 0.508)
		(drill 0.254)
		(layers "F.Cu" "B.Cu")
		(net "GND")
	)
	(via
		(at 98.592894 -283.219906)
		(size 0.4572)
		(drill 0.2032)
		(layers "F.Cu" "B.Cu")
		(net "GND")
	)
	(via
		(at 260.35 -67.147948)
		(size 0.508)
		(drill 0.254)
		(layers "F.Cu" "B.Cu")
		(net "GND")
	)
	(via
		(at 427.045882 -295.916604)
		(size 0.4572)
		(drill 0.2032)
		(layers "F.Cu" "B.Cu")
		(net "GND")
	)
	(via
		(at 205.180946 -199.01662)
		(size 0.4572)
		(drill 0.2032)
		(layers "F.Cu" "B.Cu")
		(net "GND")
	)
	(via
		(at 24.332946 -307.816758)
		(size 0.4572)
		(drill 0.2032)
		(layers "F.Cu" "B.Cu")
		(net "GND")
	)
	(via
		(at 349.946468 -62.070488)
		(size 0.508)
		(drill 0.254)
		(layers "F.Cu" "B.Cu")
		(net "GND")
	)
	(via
		(at 300.238414 -263.616694)
		(size 0.4572)
		(drill 0.2032)
		(layers "F.Cu" "B.Cu")
		(net "GND")
	)
	(via
		(at 59.842146 -300.166786)
		(size 0.4572)
		(drill 0.2032)
		(layers "F.Cu" "B.Cu")
		(net "GND")
	)
	(via
		(at 159.586676 -80.519778)
		(size 0.508)
		(drill 0.254)
		(layers "F.Cu" "B.Cu")
		(net "GND")
	)
	(via
		(at 138.424666 -218.692222)
		(size 0.4572)
		(drill 0.2032)
		(layers "F.Cu" "B.Cu")
		(net "GND")
	)
	(via
		(at 133.725666 -226.831144)
		(size 0.4572)
		(drill 0.2032)
		(layers "F.Cu" "B.Cu")
		(net "GND")
	)
	(via
		(at 277.607014 -306.116736)
		(size 0.4572)
		(drill 0.2032)
		(layers "F.Cu" "B.Cu")
		(net "GND")
	)
	(via
		(at 340.250018 -425.547282)
		(size 0.4572)
		(drill 0.2032)
		(layers "F.Cu" "B.Cu")
		(net "GND")
	)
	(via
		(at 96.243394 -275.8948)
		(size 0.4572)
		(drill 0.2032)
		(layers "F.Cu" "B.Cu")
		(net "GND")
	)
	(via
		(at 432.379882 -211.766658)
		(size 0.4572)
		(drill 0.2032)
		(layers "F.Cu" "B.Cu")
		(net "GND")
	)
	(via
		(at 116.339366 -222.761556)
		(size 0.4572)
		(drill 0.2032)
		(layers "F.Cu" "B.Cu")
		(net "GND")
	)
	(via
		(at 178.222148 -350.093788)
		(size 0.508)
		(drill 0.254)
		(layers "F.Cu" "B.Cu")
		(net "GND")
	)
	(via
		(at 285.150814 -313.766708)
		(size 0.4572)
		(drill 0.2032)
		(layers "F.Cu" "B.Cu")
		(net "GND")
	)
	(via
		(at 136.545066 -249.620024)
		(size 0.4572)
		(drill 0.2032)
		(layers "F.Cu" "B.Cu")
		(net "GND")
	)
	(via
		(at 11.135614 -308.666642)
		(size 0.4572)
		(drill 0.2032)
		(layers "F.Cu" "B.Cu")
		(net "GND")
	)
	(via
		(at 115.979194 -279.150318)
		(size 0.4572)
		(drill 0.2032)
		(layers "F.Cu" "B.Cu")
		(net "GND")
	)
	(via
		(at 161.808414 -226.216718)
		(size 0.4572)
		(drill 0.2032)
		(layers "F.Cu" "B.Cu")
		(net "GND")
	)
	(via
		(at 179.35575 -110.975394)
		(size 0.4572)
		(drill 0.254)
		(layers "F.Cu" "B.Cu")
		(net "GND")
	)
	(via
		(at 94.715838 -410.030168)
		(size 0.4064)
		(drill 0.2032)
		(layers "F.Cu" "B.Cu")
		(net "GND")
	)
	(via
		(at 442.133482 -272.966688)
		(size 0.4572)
		(drill 0.2032)
		(layers "F.Cu" "B.Cu")
		(net "GND")
	)
	(via
		(at 409.748482 -211.766658)
		(size 0.4572)
		(drill 0.2032)
		(layers "F.Cu" "B.Cu")
		(net "GND")
	)
	(via
		(at 464.764882 -210.066636)
		(size 0.4572)
		(drill 0.2032)
		(layers "F.Cu" "B.Cu")
		(net "GND")
	)
	(via
		(at 462.357978 -94.952566)
		(size 0.508)
		(drill 0.254)
		(layers "F.Cu" "B.Cu")
		(net "GND")
	)
	(via
		(at 210.514946 -231.316784)
		(size 0.4572)
		(drill 0.2032)
		(layers "F.Cu" "B.Cu")
		(net "GND")
	)
	(via
		(at 144.8308 -94.546166)
		(size 0.508)
		(drill 0.254)
		(layers "F.Cu" "B.Cu")
		(net "GND")
	)
	(via
		(at 375.56694 -335.976214)
		(size 0.49022)
		(drill 0.254)
		(layers "F.Cu" "B.Cu")
		(net "GND")
	)
	(via
		(at 292.694614 -233.016806)
		(size 0.4572)
		(drill 0.2032)
		(layers "F.Cu" "B.Cu")
		(net "GND")
	)
	(via
		(at 110.97768 -391.556748)
		(size 0.508)
		(drill 0.254)
		(layers "F.Cu" "B.Cu")
		(net "GND")
	)
	(via
		(at 455.011282 -314.616592)
		(size 0.4572)
		(drill 0.2032)
		(layers "F.Cu" "B.Cu")
		(net "GND")
	)
	(via
		(at 88.725248 -284.033722)
		(size 0.4572)
		(drill 0.2032)
		(layers "F.Cu" "B.Cu")
		(net "GND")
	)
	(via
		(at 409.243022 -401.492212)
		(size 0.4572)
		(drill 0.254)
		(layers "F.Cu" "B.Cu")
		(net "GND")
	)
	(via
		(at 447.467482 -198.166736)
		(size 0.4572)
		(drill 0.2032)
		(layers "F.Cu" "B.Cu")
		(net "GND")
	)
	(via
		(at 415.402014 -233.016806)
		(size 0.4572)
		(drill 0.2032)
		(layers "F.Cu" "B.Cu")
		(net "GND")
	)
	(via
		(at 362.039662 -266.128246)
		(size 0.4572)
		(drill 0.2032)
		(layers "F.Cu" "B.Cu")
		(net "GND")
	)
	(via
		(at 268.829282 -224.516696)
		(size 0.4572)
		(drill 0.2032)
		(layers "F.Cu" "B.Cu")
		(net "GND")
	)
	(via
		(at 78.250034 -430.147222)
		(size 0.4572)
		(drill 0.2032)
		(layers "F.Cu" "B.Cu")
		(net "GND")
	)
	(via
		(at 336.085434 -219.506038)
		(size 0.4572)
		(drill 0.2032)
		(layers "F.Cu" "B.Cu")
		(net "GND")
	)
	(via
		(at 125.847094 -266.941808)
		(size 0.4572)
		(drill 0.2032)
		(layers "F.Cu" "B.Cu")
		(net "GND")
	)
	(via
		(at 431.52568 -177.434748)
		(size 0.508)
		(drill 0.254)
		(layers "F.Cu" "B.Cu")
		(net "GND")
	)
	(via
		(at 272.273014 -221.96679)
		(size 0.4572)
		(drill 0.2032)
		(layers "F.Cu" "B.Cu")
		(net "GND")
	)
	(via
		(at 56.912256 -152.936702)
		(size 0.508)
		(drill 0.254)
		(layers "F.Cu" "B.Cu")
		(net "GND")
	)
	(via
		(at 345.953334 -238.225584)
		(size 0.4572)
		(drill 0.2032)
		(layers "F.Cu" "B.Cu")
		(net "GND")
	)
	(via
		(at 182.549546 -295.06672)
		(size 0.4572)
		(drill 0.2032)
		(layers "F.Cu" "B.Cu")
		(net "GND")
	)
	(via
		(at 214.615014 -245.76659)
		(size 0.4572)
		(drill 0.2032)
		(layers "F.Cu" "B.Cu")
		(net "GND")
	)
	(via
		(at 464.764882 -266.1666)
		(size 0.4572)
		(drill 0.2032)
		(layers "F.Cu" "B.Cu")
		(net "GND")
	)
	(via
		(at 289.250882 -207.51673)
		(size 0.4572)
		(drill 0.2032)
		(layers "F.Cu" "B.Cu")
		(net "GND")
	)
	(via
		(at 128.196594 -279.150318)
		(size 0.4572)
		(drill 0.2032)
		(layers "F.Cu" "B.Cu")
		(net "GND")
	)
	(via
		(at 335.6737 -400.224244)
		(size 0.4572)
		(drill 0.254)
		(layers "F.Cu" "B.Cu")
		(net "GND")
	)
	(via
		(at 417.076128 -216.866724)
		(size 0.4572)
		(drill 0.2032)
		(layers "F.Cu" "B.Cu")
		(net "GND")
	)
	(via
		(at 417.081716 -312.91657)
		(size 0.4572)
		(drill 0.2032)
		(layers "F.Cu" "B.Cu")
		(net "GND")
	)
	(via
		(at 29.666946 -296.766742)
		(size 0.4572)
		(drill 0.2032)
		(layers "F.Cu" "B.Cu")
		(net "GND")
	)
	(via
		(at 457.221082 -301.01667)
		(size 0.4572)
		(drill 0.2032)
		(layers "F.Cu" "B.Cu")
		(net "GND")
	)
	(via
		(at 361.460034 -245.55069)
		(size 0.4572)
		(drill 0.2032)
		(layers "F.Cu" "B.Cu")
		(net "GND")
	)
	(via
		(at 38.45687 -7.215124)
		(size 0.508)
		(drill 0.254)
		(layers "F.Cu" "B.Cu")
		(net "GND")
	)
	(via
		(at 277.607014 -309.51678)
		(size 0.4572)
		(drill 0.2032)
		(layers "F.Cu" "B.Cu")
		(net "GND")
	)
	(via
		(at 190.093346 -212.616796)
		(size 0.4572)
		(drill 0.2032)
		(layers "F.Cu" "B.Cu")
		(net "GND")
	)
	(via
		(at 331.484224 -336.982816)
		(size 0.508)
		(drill 0.254)
		(layers "F.Cu" "B.Cu")
		(net "GND")
	)
	(via
		(at 169.352214 -277.216616)
		(size 0.4572)
		(drill 0.2032)
		(layers "F.Cu" "B.Cu")
		(net "GND")
	)
	(via
		(at 121.977912 -227.64496)
		(size 0.4572)
		(drill 0.2032)
		(layers "F.Cu" "B.Cu")
		(net "GND")
	)
	(via
		(at 302.448214 -307.816758)
		(size 0.4572)
		(drill 0.2032)
		(layers "F.Cu" "B.Cu")
		(net "GND")
	)
	(via
		(at 137.82548 -26.251408)
		(size 0.508)
		(drill 0.254)
		(layers "F.Cu" "B.Cu")
		(net "GND")
	)
	(via
		(at 120.97639 -258.451604)
		(size 0.4572)
		(drill 0.2032)
		(layers "F.Cu" "B.Cu")
		(net "GND")
	)
	(via
		(at 417.997894 -171.698158)
		(size 0.49022)
		(drill 0.254)
		(layers "F.Cu" "B.Cu")
		(net "GND")
	)
	(via
		(at 389.630158 -74.534776)
		(size 0.6604)
		(drill 0.3302)
		(layers "F.Cu" "B.Cu")
		(net "GND")
	)
	(via
		(at 205.6892 -91.5924)
		(size 0.508)
		(drill 0.254)
		(layers "F.Cu" "B.Cu")
		(net "GND")
	)
	(via
		(at 296.578782 -219.41663)
		(size 0.4572)
		(drill 0.2032)
		(layers "F.Cu" "B.Cu")
		(net "GND")
	)
	(via
		(at 341.364062 -284.033722)
		(size 0.4572)
		(drill 0.2032)
		(layers "F.Cu" "B.Cu")
		(net "GND")
	)
	(via
		(at 427.766988 -10.16508)
		(size 0.508)
		(drill 0.254)
		(layers "F.Cu" "B.Cu")
		(net "GND")
	)
	(via
		(at 105.45699 -254.01524)
		(size 0.4572)
		(drill 0.2032)
		(layers "F.Cu" "B.Cu")
		(net "GND")
	)
	(via
		(at 304.122582 -291.666676)
		(size 0.4572)
		(drill 0.2032)
		(layers "F.Cu" "B.Cu")
		(net "GND")
	)
	(via
		(at 16.789146 -251.716794)
		(size 0.4572)
		(drill 0.2032)
		(layers "F.Cu" "B.Cu")
		(net "GND")
	)
	(via
		(at 407.34996 -436.347362)
		(size 0.4572)
		(drill 0.2032)
		(layers "F.Cu" "B.Cu")
		(net "GND")
	)
	(via
		(at 306.748688 -407.00452)
		(size 0.4064)
		(drill 0.2032)
		(layers "F.Cu" "B.Cu")
		(net "GND")
	)
	(via
		(at 130.906012 -238.225584)
		(size 0.4572)
		(drill 0.2032)
		(layers "F.Cu" "B.Cu")
		(net "GND")
	)
	(via
		(at 382.245616 -273.453098)
		(size 0.4572)
		(drill 0.2032)
		(layers "F.Cu" "B.Cu")
		(net "GND")
	)
	(via
		(at 241.22634 -50.365406)
		(size 0.508)
		(drill 0.254)
		(layers "F.Cu" "B.Cu")
		(net "GND")
	)
	(via
		(at 287.360614 -309.51678)
		(size 0.4572)
		(drill 0.2032)
		(layers "F.Cu" "B.Cu")
		(net "GND")
	)
	(via
		(at 107.521248 -288.917126)
		(size 0.4572)
		(drill 0.2032)
		(layers "F.Cu" "B.Cu")
		(net "GND")
	)
	(via
		(at 54.79796 -6.090412)
		(size 0.508)
		(drill 0.254)
		(layers "F.Cu" "B.Cu")
		(net "GND")
	)
	(via
		(at 182.549546 -197.316598)
		(size 0.4572)
		(drill 0.2032)
		(layers "F.Cu" "B.Cu")
		(net "GND")
	)
	(via
		(at 7.035546 -201.56678)
		(size 0.4572)
		(drill 0.2032)
		(layers "F.Cu" "B.Cu")
		(net "GND")
	)
	(via
		(at 377.90628 -239.853216)
		(size 0.4572)
		(drill 0.2032)
		(layers "F.Cu" "B.Cu")
		(net "GND")
	)
	(via
		(at 90.20937 -410.664152)
		(size 0.4572)
		(drill 0.254)
		(layers "F.Cu" "B.Cu")
		(net "GND")
	)
	(via
		(at 378.486162 -286.475424)
		(size 0.4572)
		(drill 0.2032)
		(layers "F.Cu" "B.Cu")
		(net "GND")
	)
	(via
		(at 350.807274 -166.720012)
		(size 0.508)
		(drill 0.254)
		(layers "F.Cu" "B.Cu")
		(net "GND")
	)
	(via
		(at 13.345414 -244.066568)
		(size 0.4572)
		(drill 0.2032)
		(layers "F.Cu" "B.Cu")
		(net "GND")
	)
	(via
		(at 289.250882 -286.56661)
		(size 0.4572)
		(drill 0.2032)
		(layers "F.Cu" "B.Cu")
		(net "GND")
	)
	(via
		(at 422.945814 -242.3668)
		(size 0.4572)
		(drill 0.2032)
		(layers "F.Cu" "B.Cu")
		(net "GND")
	)
	(via
		(at 311.882282 -250.866656)
		(size 0.4572)
		(drill 0.2032)
		(layers "F.Cu" "B.Cu")
		(net "GND")
	)
	(via
		(at 52.298346 -270.416782)
		(size 0.4572)
		(drill 0.2032)
		(layers "F.Cu" "B.Cu")
		(net "GND")
	)
	(via
		(at 422.945814 -313.766708)
		(size 0.4572)
		(drill 0.2032)
		(layers "F.Cu" "B.Cu")
		(net "GND")
	)
	(via
		(at 442.133482 -275.516594)
		(size 0.4572)
		(drill 0.2032)
		(layers "F.Cu" "B.Cu")
		(net "GND")
	)
	(via
		(at 349.71228 -246.364506)
		(size 0.4572)
		(drill 0.2032)
		(layers "F.Cu" "B.Cu")
		(net "GND")
	)
	(via
		(at 443.367414 -250.016772)
		(size 0.4572)
		(drill 0.2032)
		(layers "F.Cu" "B.Cu")
		(net "GND")
	)
	(via
		(at 296.578782 -235.566712)
		(size 0.4572)
		(drill 0.2032)
		(layers "F.Cu" "B.Cu")
		(net "GND")
	)
	(via
		(at 268.829282 -316.316614)
		(size 0.4572)
		(drill 0.2032)
		(layers "F.Cu" "B.Cu")
		(net "GND")
	)
	(via
		(at 190.093346 -272.116804)
		(size 0.4572)
		(drill 0.2032)
		(layers "F.Cu" "B.Cu")
		(net "GND")
	)
	(via
		(at 345.15171 -54.354476)
		(size 0.4572)
		(drill 0.2032)
		(layers "F.Cu" "B.Cu")
		(net "GND")
	)
	(via
		(at 108.43387 -252.659388)
		(size 0.4572)
		(drill 0.2032)
		(layers "F.Cu" "B.Cu")
		(net "GND")
	)
	(via
		(at 136.654794 -272.639282)
		(size 0.4572)
		(drill 0.2032)
		(layers "F.Cu" "B.Cu")
		(net "GND")
	)
	(via
		(at 422.945814 -248.31675)
		(size 0.4572)
		(drill 0.2032)
		(layers "F.Cu" "B.Cu")
		(net "GND")
	)
	(via
		(at 285.150814 -278.066754)
		(size 0.4572)
		(drill 0.2032)
		(layers "F.Cu" "B.Cu")
		(net "GND")
	)
	(via
		(at 133.00964 -82.098388)
		(size 0.508)
		(drill 0.254)
		(layers "F.Cu" "B.Cu")
		(net "GND")
	)
	(via
		(at 331.351636 -401.492212)
		(size 0.4572)
		(drill 0.254)
		(layers "F.Cu" "B.Cu")
		(net "GND")
	)
	(via
		(at 329.7301 -336.097118)
		(size 0.508)
		(drill 0.254)
		(layers "F.Cu" "B.Cu")
		(net "GND")
	)
	(via
		(at 338.40039 -57.45734)
		(size 0.4572)
		(drill 0.2032)
		(layers "F.Cu" "B.Cu")
		(net "GND")
	)
	(via
		(at 392.209782 -409.396184)
		(size 0.4572)
		(drill 0.254)
		(layers "F.Cu" "B.Cu")
		(net "GND")
	)
	(via
		(at 289.250882 -211.766658)
		(size 0.4572)
		(drill 0.2032)
		(layers "F.Cu" "B.Cu")
		(net "GND")
	)
	(via
		(at 327.250044 -435.0512)
		(size 0.4572)
		(drill 0.2032)
		(layers "F.Cu" "B.Cu")
		(net "GND")
	)
	(via
		(at 14.579346 -263.616694)
		(size 0.4572)
		(drill 0.2032)
		(layers "F.Cu" "B.Cu")
		(net "GND")
	)
	(via
		(at 140.062966 -248.680478)
		(size 0.4572)
		(drill 0.2032)
		(layers "F.Cu" "B.Cu")
		(net "GND")
	)
	(via
		(at 374.257062 -261.244842)
		(size 0.4572)
		(drill 0.2032)
		(layers "F.Cu" "B.Cu")
		(net "GND")
	)
	(via
		(at 179.105814 -250.866656)
		(size 0.4572)
		(drill 0.2032)
		(layers "F.Cu" "B.Cu")
		(net "GND")
	)
	(via
		(at 375.463562 -103.176578)
		(size 0.508)
		(drill 0.254)
		(layers "F.Cu" "B.Cu")
		(net "GND")
	)
	(via
		(at 443.367414 -221.96679)
		(size 0.4572)
		(drill 0.2032)
		(layers "F.Cu" "B.Cu")
		(net "GND")
	)
	(via
		(at 360.98988 -238.225584)
		(size 0.4572)
		(drill 0.2032)
		(layers "F.Cu" "B.Cu")
		(net "GND")
	)
	(via
		(at 345.483434 -219.506038)
		(size 0.4572)
		(drill 0.2032)
		(layers "F.Cu" "B.Cu")
		(net "GND")
	)
	(via
		(at 259.440426 -77.648816)
		(size 0.508)
		(drill 0.254)
		(layers "F.Cu" "B.Cu")
		(net "GND")
	)
	(via
		(at 126.677166 -242.294918)
		(size 0.4572)
		(drill 0.2032)
		(layers "F.Cu" "B.Cu")
		(net "GND")
	)
	(via
		(at 383.545334 -218.692222)
		(size 0.4572)
		(drill 0.2032)
		(layers "F.Cu" "B.Cu")
		(net "GND")
	)
	(via
		(at 243.551964 -168.244012)
		(size 0.508)
		(drill 0.254)
		(layers "F.Cu" "B.Cu")
		(net "GND")
	)
	(via
		(at 462.555082 -250.866656)
		(size 0.4572)
		(drill 0.2032)
		(layers "F.Cu" "B.Cu")
		(net "GND")
	)
	(via
		(at 202.971146 -290.816792)
		(size 0.4572)
		(drill 0.2032)
		(layers "F.Cu" "B.Cu")
		(net "GND")
	)
	(via
		(at 157.48762 -47.950628)
		(size 0.508)
		(drill 0.254)
		(layers "F.Cu" "B.Cu")
		(net "GND")
	)
	(via
		(at 214.615014 -282.316682)
		(size 0.4572)
		(drill 0.2032)
		(layers "F.Cu" "B.Cu")
		(net "GND")
	)
	(via
		(at 412.306262 -400.224244)
		(size 0.4572)
		(drill 0.254)
		(layers "F.Cu" "B.Cu")
		(net "GND")
	)
	(via
		(at 94.833694 -253.919736)
		(size 0.4572)
		(drill 0.2032)
		(layers "F.Cu" "B.Cu")
		(net "GND")
	)
	(via
		(at 349.242634 -230.900478)
		(size 0.4572)
		(drill 0.2032)
		(layers "F.Cu" "B.Cu")
		(net "GND")
	)
	(via
		(at 89.554812 -249.620024)
		(size 0.4572)
		(drill 0.2032)
		(layers "F.Cu" "B.Cu")
		(net "GND")
	)
	(via
		(at 401.349972 -432.451256)
		(size 0.4572)
		(drill 0.2032)
		(layers "F.Cu" "B.Cu")
		(net "GND")
	)
	(via
		(at 314.092082 -306.96662)
		(size 0.4572)
		(drill 0.2032)
		(layers "F.Cu" "B.Cu")
		(net "GND")
	)
	(via
		(at 132.895848 -254.733552)
		(size 0.4572)
		(drill 0.2032)
		(layers "F.Cu" "B.Cu")
		(net "GND")
	)
	(via
		(at 342.161368 -403.883876)
		(size 0.4064)
		(drill 0.2032)
		(layers "F.Cu" "B.Cu")
		(net "GND")
	)
	(via
		(at 448.8942 -118.336822)
		(size 0.508)
		(drill 0.254)
		(layers "F.Cu" "B.Cu")
		(net "GND")
	)
	(via
		(at 33.629854 -131.157472)
		(size 0.508)
		(drill 0.254)
		(layers "F.Cu" "B.Cu")
		(net "GND")
	)
	(via
		(at 356.4509 -386.41909)
		(size 0.508)
		(drill 0.254)
		(layers "F.Cu" "B.Cu")
		(net "GND")
	)
	(via
		(at 340.784434 -243.922804)
		(size 0.4572)
		(drill 0.2032)
		(layers "F.Cu" "B.Cu")
		(net "GND")
	)
	(via
		(at 403.349968 -435.0512)
		(size 0.4572)
		(drill 0.2032)
		(layers "F.Cu" "B.Cu")
		(net "GND")
	)
	(via
		(at 164.018214 -264.466578)
		(size 0.4572)
		(drill 0.2032)
		(layers "F.Cu" "B.Cu")
		(net "GND")
	)
	(via
		(at 95.17126 -414.4518)
		(size 0.508)
		(drill 0.254)
		(layers "F.Cu" "B.Cu")
		(net "GND")
	)
	(via
		(at 120.97639 -236.252004)
		(size 0.4572)
		(drill 0.2032)
		(layers "F.Cu" "B.Cu")
		(net "GND")
	)
	(via
		(at 431.295556 -107.70997)
		(size 0.508)
		(drill 0.254)
		(layers "F.Cu" "B.Cu")
		(net "GND")
	)
	(via
		(at 318.64046 -407.638504)
		(size 0.4572)
		(drill 0.254)
		(layers "F.Cu" "B.Cu")
		(net "GND")
	)
	(via
		(at 328.62647 -341.063072)
		(size 0.49022)
		(drill 0.254)
		(layers "F.Cu" "B.Cu")
		(net "GND")
	)
	(via
		(at 415.402014 -258.516628)
		(size 0.4572)
		(drill 0.2032)
		(layers "F.Cu" "B.Cu")
		(net "GND")
	)
	(via
		(at 181.407308 -52.893722)
		(size 0.508)
		(drill 0.254)
		(layers "F.Cu" "B.Cu")
		(net "GND")
	)
	(via
		(at 386.541518 -404.51786)
		(size 0.4572)
		(drill 0.254)
		(layers "F.Cu" "B.Cu")
		(net "GND")
	)
	(via
		(at 378.933964 -441.225432)
		(size 0.508)
		(drill 0.254)
		(layers "F.Cu" "B.Cu")
		(net "GND")
	)
	(via
		(at 19.38909 -18.502376)
		(size 0.508)
		(drill 0.254)
		(layers "F.Cu" "B.Cu")
		(net "GND")
	)
	(via
		(at 302.448214 -285.716726)
		(size 0.4572)
		(drill 0.2032)
		(layers "F.Cu" "B.Cu")
		(net "GND")
	)
	(via
		(at 338.250022 -433.747164)
		(size 0.4572)
		(drill 0.2032)
		(layers "F.Cu" "B.Cu")
		(net "GND")
	)
	(via
		(at 56.049672 -156.446474)
		(size 0.49022)
		(drill 0.254)
		(layers "F.Cu" "B.Cu")
		(net "GND")
	)
	(via
		(at 270.063214 -204.96657)
		(size 0.4572)
		(drill 0.2032)
		(layers "F.Cu" "B.Cu")
		(net "GND")
	)
	(via
		(at 59.673998 -400.858228)
		(size 0.4064)
		(drill 0.2032)
		(layers "F.Cu" "B.Cu")
		(net "GND")
	)
	(via
		(at 9.245346 -204.96657)
		(size 0.4572)
		(drill 0.2032)
		(layers "F.Cu" "B.Cu")
		(net "GND")
	)
	(via
		(at 126.207012 -231.714548)
		(size 0.4572)
		(drill 0.2032)
		(layers "F.Cu" "B.Cu")
		(net "GND")
	)
	(via
		(at 276.373082 -291.666676)
		(size 0.4572)
		(drill 0.2032)
		(layers "F.Cu" "B.Cu")
		(net "GND")
	)
	(via
		(at 184.923176 -351.557082)
		(size 0.508)
		(drill 0.254)
		(layers "F.Cu" "B.Cu")
		(net "GND")
	)
	(via
		(at 302.9204 -55.286148)
		(size 0.508)
		(drill 0.254)
		(layers "F.Cu" "B.Cu")
		(net "GND")
	)
	(via
		(at 184.439814 -314.616592)
		(size 0.4572)
		(drill 0.2032)
		(layers "F.Cu" "B.Cu")
		(net "GND")
	)
	(via
		(at 350.705674 -181.916832)
		(size 0.508)
		(drill 0.254)
		(layers "F.Cu" "B.Cu")
		(net "GND")
	)
	(via
		(at 43.85691 -9.424924)
		(size 0.508)
		(drill 0.254)
		(layers "F.Cu" "B.Cu")
		(net "GND")
	)
	(via
		(at 327.217532 -36.957254)
		(size 0.49022)
		(drill 0.254)
		(layers "F.Cu" "B.Cu")
		(net "GND")
	)
	(via
		(at 121.978166 -219.506038)
		(size 0.4572)
		(drill 0.2032)
		(layers "F.Cu" "B.Cu")
		(net "GND")
	)
	(via
		(at 2.764536 -81.710022)
		(size 0.508)
		(drill 0.254)
		(layers "F.Cu" "B.Cu")
		(net "GND")
	)
	(via
		(at 260.002782 -69.231256)
		(size 0.508)
		(drill 0.254)
		(layers "F.Cu" "B.Cu")
		(net "GND")
	)
	(via
		(at 383.545334 -247.992138)
		(size 0.4572)
		(drill 0.2032)
		(layers "F.Cu" "B.Cu")
		(net "GND")
	)
	(via
		(at 123.967748 -281.59202)
		(size 0.4572)
		(drill 0.2032)
		(layers "F.Cu" "B.Cu")
		(net "GND")
	)
	(via
		(at 161.808414 -294.216582)
		(size 0.4572)
		(drill 0.2032)
		(layers "F.Cu" "B.Cu")
		(net "GND")
	)
	(via
		(at 48.638714 -210.066636)
		(size 0.4572)
		(drill 0.2032)
		(layers "F.Cu" "B.Cu")
		(net "GND")
	)
	(via
		(at 270.063214 -292.516814)
		(size 0.4572)
		(drill 0.2032)
		(layers "F.Cu" "B.Cu")
		(net "GND")
	)
	(via
		(at 131.015994 -282.405836)
		(size 0.4572)
		(drill 0.2032)
		(layers "F.Cu" "B.Cu")
		(net "GND")
	)
	(via
		(at 268.829282 -258.516628)
		(size 0.4572)
		(drill 0.2032)
		(layers "F.Cu" "B.Cu")
		(net "GND")
	)
	(via
		(at 428.279814 -201.56678)
		(size 0.4572)
		(drill 0.2032)
		(layers "F.Cu" "B.Cu")
		(net "GND")
	)
	(via
		(at 89.664794 -259.616956)
		(size 0.4572)
		(drill 0.2032)
		(layers "F.Cu" "B.Cu")
		(net "GND")
	)
	(via
		(at 410.660596 -18.491454)
		(size 0.508)
		(drill 0.254)
		(layers "F.Cu" "B.Cu")
		(net "GND")
	)
	(via
		(at 353.941634 -226.017328)
		(size 0.4572)
		(drill 0.2032)
		(layers "F.Cu" "B.Cu")
		(net "GND")
	)
	(via
		(at 441.376816 -46.517306)
		(size 0.508)
		(drill 0.254)
		(layers "F.Cu" "B.Cu")
		(net "GND")
	)
	(via
		(at 162.912044 -428.569882)
		(size 0.508)
		(drill 0.254)
		(layers "F.Cu" "B.Cu")
		(net "GND")
	)
	(via
		(at 236.780832 -439.905394)
		(size 0.508)
		(drill 0.254)
		(layers "F.Cu" "B.Cu")
		(net "GND")
	)
	(via
		(at 140.941806 -410.664152)
		(size 0.4572)
		(drill 0.254)
		(layers "F.Cu" "B.Cu")
		(net "GND")
	)
	(via
		(at 431.696622 -362.809536)
		(size 0.508)
		(drill 0.254)
		(layers "F.Cu" "B.Cu")
		(net "GND")
	)
	(via
		(at 93.27261 -407.638504)
		(size 0.4572)
		(drill 0.254)
		(layers "F.Cu" "B.Cu")
		(net "GND")
	)
	(via
		(at 186.649614 -211.766658)
		(size 0.4572)
		(drill 0.2032)
		(layers "F.Cu" "B.Cu")
		(net "GND")
	)
	(via
		(at 177.75555 -111.775494)
		(size 0.4572)
		(drill 0.254)
		(layers "F.Cu" "B.Cu")
		(net "GND")
	)
	(via
		(at 292.84422 -415.00552)
		(size 0.508)
		(drill 0.254)
		(layers "F.Cu" "B.Cu")
		(net "GND")
	)
	(via
		(at 443.888114 -43.620182)
		(size 0.508)
		(drill 0.254)
		(layers "F.Cu" "B.Cu")
		(net "GND")
	)
	(via
		(at 86.250018 -427.699678)
		(size 0.4572)
		(drill 0.2032)
		(layers "F.Cu" "B.Cu")
		(net "GND")
	)
	(via
		(at 106.426508 -406.477724)
		(size 0.508)
		(drill 0.254)
		(layers "F.Cu" "B.Cu")
		(net "GND")
	)
	(via
		(at 138.065002 -255.547368)
		(size 0.4318)
		(drill 0.2032)
		(layers "F.Cu" "B.Cu")
		(net "GND")
	)
	(via
		(at 130.405886 -403.249892)
		(size 0.4572)
		(drill 0.254)
		(layers "F.Cu" "B.Cu")
		(net "GND")
	)
	(via
		(at 139.834366 -226.017328)
		(size 0.4572)
		(drill 0.2032)
		(layers "F.Cu" "B.Cu")
		(net "GND")
	)
	(via
		(at 61.020198 -407.00452)
		(size 0.4064)
		(drill 0.2032)
		(layers "F.Cu" "B.Cu")
		(net "GND")
	)
	(via
		(at 416.575494 -171.068238)
		(size 0.49022)
		(drill 0.254)
		(layers "F.Cu" "B.Cu")
		(net "GND")
	)
	(via
		(at 162.384486 -410.664152)
		(size 0.4572)
		(drill 0.254)
		(layers "F.Cu" "B.Cu")
		(net "GND")
	)
	(via
		(at 355.461316 -288.917126)
		(size 0.4572)
		(drill 0.2032)
		(layers "F.Cu" "B.Cu")
		(net "GND")
	)
	(via
		(at 414.070292 -180.810154)
		(size 0.49022)
		(drill 0.254)
		(layers "F.Cu" "B.Cu")
		(net "GND")
	)
	(via
		(at 404.920958 -401.492212)
		(size 0.4572)
		(drill 0.254)
		(layers "F.Cu" "B.Cu")
		(net "GND")
	)
	(via
		(at 386.18033 -400.858228)
		(size 0.4064)
		(drill 0.2032)
		(layers "F.Cu" "B.Cu")
		(net "GND")
	)
	(via
		(at 11.135614 -280.61666)
		(size 0.4572)
		(drill 0.2032)
		(layers "F.Cu" "B.Cu")
		(net "GND")
	)
	(via
		(at 332.336648 -410.030168)
		(size 0.4064)
		(drill 0.2032)
		(layers "F.Cu" "B.Cu")
		(net "GND")
	)
	(via
		(at 340.017608 -136.310116)
		(size 0.508)
		(drill 0.254)
		(layers "F.Cu" "B.Cu")
		(net "GND")
	)
	(via
		(at 16.789146 -295.06672)
		(size 0.4572)
		(drill 0.2032)
		(layers "F.Cu" "B.Cu")
		(net "GND")
	)
	(via
		(at 130.546094 -278.336502)
		(size 0.4572)
		(drill 0.2032)
		(layers "F.Cu" "B.Cu")
		(net "GND")
	)
	(via
		(at 365.76381 -257.692906)
		(size 0.4572)
		(drill 0.2032)
		(layers "F.Cu" "B.Cu")
		(net "GND")
	)
	(via
		(at 104.121966 -226.017328)
		(size 0.4572)
		(drill 0.2032)
		(layers "F.Cu" "B.Cu")
		(net "GND")
	)
	(via
		(at 177.75555 -118.975378)
		(size 0.4572)
		(drill 0.254)
		(layers "F.Cu" "B.Cu")
		(net "GND")
	)
	(via
		(at 306.548282 -216.866724)
		(size 0.4572)
		(drill 0.2032)
		(layers "F.Cu" "B.Cu")
		(net "GND")
	)
	(via
		(at 453.121014 -216.016586)
		(size 0.4572)
		(drill 0.2032)
		(layers "F.Cu" "B.Cu")
		(net "GND")
	)
	(via
		(at 311.882282 -233.86669)
		(size 0.4572)
		(drill 0.2032)
		(layers "F.Cu" "B.Cu")
		(net "GND")
	)
	(via
		(at 458.455014 -265.316716)
		(size 0.4572)
		(drill 0.2032)
		(layers "F.Cu" "B.Cu")
		(net "GND")
	)
	(via
		(at 362.399834 -229.272846)
		(size 0.4572)
		(drill 0.2032)
		(layers "F.Cu" "B.Cu")
		(net "GND")
	)
	(via
		(at 41.310814 -221.116652)
		(size 0.4572)
		(drill 0.2032)
		(layers "F.Cu" "B.Cu")
		(net "GND")
	)
	(via
		(at 172.795946 -199.01662)
		(size 0.4572)
		(drill 0.2032)
		(layers "F.Cu" "B.Cu")
		(net "GND")
	)
	(via
		(at 53.510688 -4.962652)
		(size 0.508)
		(drill 0.254)
		(layers "F.Cu" "B.Cu")
		(net "GND")
	)
	(via
		(at 32.337502 -165.04031)
		(size 0.508)
		(drill 0.254)
		(layers "F.Cu" "B.Cu")
		(net "GND")
	)
	(via
		(at 159.779462 -403.249892)
		(size 0.4572)
		(drill 0.254)
		(layers "F.Cu" "B.Cu")
		(net "GND")
	)
	(via
		(at 2.764536 -274.750022)
		(size 0.508)
		(drill 0.254)
		(layers "F.Cu" "B.Cu")
		(net "GND")
	)
	(via
		(at 424.836082 -241.516662)
		(size 0.4572)
		(drill 0.2032)
		(layers "F.Cu" "B.Cu")
		(net "GND")
	)
	(via
		(at 120.97639 -237.420404)
		(size 0.4572)
		(drill 0.2032)
		(layers "F.Cu" "B.Cu")
		(net "GND")
	)
	(via
		(at 337.604608 -288.917126)
		(size 0.4572)
		(drill 0.2032)
		(layers "F.Cu" "B.Cu")
		(net "GND")
	)
	(via
		(at 119.596154 -400.858228)
		(size 0.4064)
		(drill 0.2032)
		(layers "F.Cu" "B.Cu")
		(net "GND")
	)
	(via
		(at 376.472196 -357.355394)
		(size 0.508)
		(drill 0.254)
		(layers "F.Cu" "B.Cu")
		(net "GND")
	)
	(via
		(at 358.280462 -256.361438)
		(size 0.4572)
		(drill 0.2032)
		(layers "F.Cu" "B.Cu")
		(net "GND")
	)
	(via
		(at 210.514946 -272.116804)
		(size 0.4572)
		(drill 0.2032)
		(layers "F.Cu" "B.Cu")
		(net "GND")
	)
	(via
		(at 337.0199 -406.370536)
		(size 0.4572)
		(drill 0.254)
		(layers "F.Cu" "B.Cu")
		(net "GND")
	)
	(via
		(at 384.124962 -278.336502)
		(size 0.4572)
		(drill 0.2032)
		(layers "F.Cu" "B.Cu")
		(net "GND")
	)
	(via
		(at 171.7675 -354.115878)
		(size 0.49022)
		(drill 0.254)
		(layers "F.Cu" "B.Cu")
		(net "GND")
	)
	(via
		(at 111.614458 -201.48677)
		(size 0.6604)
		(drill 0.3302)
		(layers "F.Cu" "B.Cu")
		(net "GND")
	)
	(via
		(at 259.588 -67.147948)
		(size 0.508)
		(drill 0.254)
		(layers "F.Cu" "B.Cu")
		(net "GND")
	)
	(via
		(at 117.964458 -331.56652)
		(size 0.508)
		(drill 0.254)
		(layers "F.Cu" "B.Cu")
		(net "GND")
	)
	(via
		(at 130.350006 -437.49976)
		(size 0.4572)
		(drill 0.2032)
		(layers "F.Cu" "B.Cu")
		(net "GND")
	)
	(via
		(at 52.465478 -400.858228)
		(size 0.4064)
		(drill 0.2032)
		(layers "F.Cu" "B.Cu")
		(net "GND")
	)
	(via
		(at 349.822262 -254.733552)
		(size 0.4572)
		(drill 0.2032)
		(layers "F.Cu" "B.Cu")
		(net "GND")
	)
	(via
		(at 375.667016 -263.686544)
		(size 0.4572)
		(drill 0.2032)
		(layers "F.Cu" "B.Cu")
		(net "GND")
	)
	(via
		(at 464.764882 -291.666676)
		(size 0.4572)
		(drill 0.2032)
		(layers "F.Cu" "B.Cu")
		(net "GND")
	)
	(via
		(at 122.558048 -275.8948)
		(size 0.4572)
		(drill 0.2032)
		(layers "F.Cu" "B.Cu")
		(net "GND")
	)
	(via
		(at 385.09829 -403.883876)
		(size 0.4064)
		(drill 0.2032)
		(layers "F.Cu" "B.Cu")
		(net "GND")
	)
	(via
		(at 385.534662 -267.755878)
		(size 0.4572)
		(drill 0.2032)
		(layers "F.Cu" "B.Cu")
		(net "GND")
	)
	(via
		(at 345.95308 -241.481102)
		(size 0.4572)
		(drill 0.2032)
		(layers "F.Cu" "B.Cu")
		(net "GND")
	)
	(via
		(at 38.395402 -351.486978)
		(size 0.508)
		(drill 0.254)
		(layers "F.Cu" "B.Cu")
		(net "GND")
	)
	(via
		(at 421.23106 -358.754172)
		(size 0.508)
		(drill 0.254)
		(layers "F.Cu" "B.Cu")
		(net "GND")
	)
	(via
		(at 432.37658 -140.396468)
		(size 0.508)
		(drill 0.254)
		(layers "F.Cu" "B.Cu")
		(net "GND")
	)
	(via
		(at 369.448334 -226.831144)
		(size 0.4572)
		(drill 0.2032)
		(layers "F.Cu" "B.Cu")
		(net "GND")
	)
	(via
		(at 355.96576 -330.42352)
		(size 0.508)
		(drill 0.254)
		(layers "F.Cu" "B.Cu")
		(net "GND")
	)
	(via
		(at 377.351798 -404.51786)
		(size 0.4572)
		(drill 0.254)
		(layers "F.Cu" "B.Cu")
		(net "GND")
	)
	(via
		(at 293.82466 -94.800674)
		(size 0.508)
		(drill 0.254)
		(layers "F.Cu" "B.Cu")
		(net "GND")
	)
	(via
		(at 113.989866 -217.064336)
		(size 0.4572)
		(drill 0.2032)
		(layers "F.Cu" "B.Cu")
		(net "GND")
	)
	(via
		(at 369.427506 -170.246548)
		(size 0.508)
		(drill 0.254)
		(layers "F.Cu" "B.Cu")
		(net "GND")
	)
	(via
		(at 339.844634 -242.294918)
		(size 0.4572)
		(drill 0.2032)
		(layers "F.Cu" "B.Cu")
		(net "GND")
	)
	(via
		(at 18.679414 -303.566576)
		(size 0.4572)
		(drill 0.2032)
		(layers "F.Cu" "B.Cu")
		(net "GND")
	)
	(via
		(at 29.666946 -212.616796)
		(size 0.4572)
		(drill 0.2032)
		(layers "F.Cu" "B.Cu")
		(net "GND")
	)
	(via
		(at 419.9001 -5.585714)
		(size 0.508)
		(drill 0.254)
		(layers "F.Cu" "B.Cu")
		(net "GND")
	)
	(via
		(at 205.180946 -233.016806)
		(size 0.4572)
		(drill 0.2032)
		(layers "F.Cu" "B.Cu")
		(net "GND")
	)
	(via
		(at 109.760766 -226.017328)
		(size 0.4572)
		(drill 0.2032)
		(layers "F.Cu" "B.Cu")
		(net "GND")
	)
	(via
		(at 412.195772 -18.235422)
		(size 0.508)
		(drill 0.254)
		(layers "F.Cu" "B.Cu")
		(net "GND")
	)
	(via
		(at 126.676912 -232.528364)
		(size 0.4572)
		(drill 0.2032)
		(layers "F.Cu" "B.Cu")
		(net "GND")
	)
	(via
		(at 29.666946 -229.616762)
		(size 0.4572)
		(drill 0.2032)
		(layers "F.Cu" "B.Cu")
		(net "GND")
	)
	(via
		(at 96.713294 -286.475424)
		(size 0.4572)
		(drill 0.2032)
		(layers "F.Cu" "B.Cu")
		(net "GND")
	)
	(via
		(at 270.063214 -199.01662)
		(size 0.4572)
		(drill 0.2032)
		(layers "F.Cu" "B.Cu")
		(net "GND")
	)
	(via
		(at 409.748482 -305.266598)
		(size 0.4572)
		(drill 0.2032)
		(layers "F.Cu" "B.Cu")
		(net "GND")
	)
	(via
		(at 415.402014 -203.266802)
		(size 0.4572)
		(drill 0.2032)
		(layers "F.Cu" "B.Cu")
		(net "GND")
	)
	(via
		(at 118.798594 -282.405836)
		(size 0.4572)
		(drill 0.2032)
		(layers "F.Cu" "B.Cu")
		(net "GND")
	)
	(via
		(at 407.866596 -18.235422)
		(size 0.508)
		(drill 0.254)
		(layers "F.Cu" "B.Cu")
		(net "GND")
	)
	(via
		(at 205.180946 -315.46673)
		(size 0.4572)
		(drill 0.2032)
		(layers "F.Cu" "B.Cu")
		(net "GND")
	)
	(via
		(at 183.57088 -132.425948)
		(size 0.508)
		(drill 0.254)
		(layers "F.Cu" "B.Cu")
		(net "GND")
	)
	(via
		(at 139.83843 -37.414708)
		(size 0.508)
		(drill 0.254)
		(layers "F.Cu" "B.Cu")
		(net "GND")
	)
	(via
		(at 264.729214 -260.21665)
		(size 0.4572)
		(drill 0.2032)
		(layers "F.Cu" "B.Cu")
		(net "GND")
	)
	(via
		(at 271.174972 -69.5452)
		(size 0.508)
		(drill 0.254)
		(layers "F.Cu" "B.Cu")
		(net "GND")
	)
	(via
		(at 24.223726 -4.328668)
		(size 0.508)
		(drill 0.254)
		(layers "F.Cu" "B.Cu")
		(net "GND")
	)
	(via
		(at 169.352214 -316.316614)
		(size 0.4572)
		(drill 0.2032)
		(layers "F.Cu" "B.Cu")
		(net "GND")
	)
	(via
		(at 410.95041 -407.00452)
		(size 0.4064)
		(drill 0.2032)
		(layers "F.Cu" "B.Cu")
		(net "GND")
	)
	(via
		(at 94.723966 -216.25052)
		(size 0.4572)
		(drill 0.2032)
		(layers "F.Cu" "B.Cu")
		(net "GND")
	)
	(via
		(at 359.223056 -365.631476)
		(size 0.508)
		(drill 0.254)
		(layers "F.Cu" "B.Cu")
		(net "GND")
	)
	(via
		(at 409.60802 -360.385868)
		(size 0.508)
		(drill 0.254)
		(layers "F.Cu" "B.Cu")
		(net "GND")
	)
	(via
		(at 368.916204 -250.85675)
		(size 0.4572)
		(drill 0.2032)
		(layers "F.Cu" "B.Cu")
		(net "GND")
	)
	(via
		(at 467.535514 -363.08538)
		(size 0.508)
		(drill 0.254)
		(layers "F.Cu" "B.Cu")
		(net "GND")
	)
	(via
		(at 254.975614 -204.96657)
		(size 0.4572)
		(drill 0.2032)
		(layers "F.Cu" "B.Cu")
		(net "GND")
	)
	(via
		(at 375.667016 -262.058658)
		(size 0.4572)
		(drill 0.2032)
		(layers "F.Cu" "B.Cu")
		(net "GND")
	)
	(via
		(at 94.723966 -230.900478)
		(size 0.4572)
		(drill 0.2032)
		(layers "F.Cu" "B.Cu")
		(net "GND")
	)
	(via
		(at 13.345414 -247.466612)
		(size 0.4572)
		(drill 0.2032)
		(layers "F.Cu" "B.Cu")
		(net "GND")
	)
	(via
		(at 37.760402 -351.486978)
		(size 0.508)
		(drill 0.254)
		(layers "F.Cu" "B.Cu")
		(net "GND")
	)
	(via
		(at 378.846334 -220.319854)
		(size 0.4572)
		(drill 0.2032)
		(layers "F.Cu" "B.Cu")
		(net "GND")
	)
	(via
		(at 212.724746 -298.466764)
		(size 0.4572)
		(drill 0.2032)
		(layers "F.Cu" "B.Cu")
		(net "GND")
	)
	(via
		(at 291.460682 -239.81664)
		(size 0.4572)
		(drill 0.2032)
		(layers "F.Cu" "B.Cu")
		(net "GND")
	)
	(via
		(at 277.607014 -246.616728)
		(size 0.4572)
		(drill 0.2032)
		(layers "F.Cu" "B.Cu")
		(net "GND")
	)
	(via
		(at 211.6582 -98.171)
		(size 0.508)
		(drill 0.254)
		(layers "F.Cu" "B.Cu")
		(net "GND")
	)
	(via
		(at 216.824814 -299.316648)
		(size 0.4572)
		(drill 0.2032)
		(layers "F.Cu" "B.Cu")
		(net "GND")
	)
	(via
		(at 198.47814 -109.682788)
		(size 0.508)
		(drill 0.254)
		(layers "F.Cu" "B.Cu")
		(net "GND")
	)
	(via
		(at 199.527414 -284.866588)
		(size 0.4572)
		(drill 0.2032)
		(layers "F.Cu" "B.Cu")
		(net "GND")
	)
	(via
		(at 439.923682 -269.566644)
		(size 0.4572)
		(drill 0.2032)
		(layers "F.Cu" "B.Cu")
		(net "GND")
	)
	(via
		(at 157.708346 -300.166786)
		(size 0.4572)
		(drill 0.2032)
		(layers "F.Cu" "B.Cu")
		(net "GND")
	)
	(via
		(at 59.842146 -268.71676)
		(size 0.4572)
		(drill 0.2032)
		(layers "F.Cu" "B.Cu")
		(net "GND")
	)
	(via
		(at 413.192214 -208.366614)
		(size 0.4572)
		(drill 0.2032)
		(layers "F.Cu" "B.Cu")
		(net "GND")
	)
	(via
		(at 281.707082 -198.166736)
		(size 0.4572)
		(drill 0.2032)
		(layers "F.Cu" "B.Cu")
		(net "GND")
	)
	(via
		(at 52.730908 -192.24117)
		(size 0.508)
		(drill 0.254)
		(layers "F.Cu" "B.Cu")
		(net "GND")
	)
	(via
		(at 411.958282 -228.766624)
		(size 0.4572)
		(drill 0.2032)
		(layers "F.Cu" "B.Cu")
		(net "GND")
	)
	(via
		(at 165.905942 -401.492212)
		(size 0.4572)
		(drill 0.254)
		(layers "F.Cu" "B.Cu")
		(net "GND")
	)
	(via
		(at 264.729214 -221.96679)
		(size 0.4572)
		(drill 0.2032)
		(layers "F.Cu" "B.Cu")
		(net "GND")
	)
	(via
		(at 443.367414 -296.766742)
		(size 0.4572)
		(drill 0.2032)
		(layers "F.Cu" "B.Cu")
		(net "GND")
	)
	(via
		(at 296.794682 -200.716642)
		(size 0.4572)
		(drill 0.2032)
		(layers "F.Cu" "B.Cu")
		(net "GND")
	)
	(via
		(at 324.76694 -409.396184)
		(size 0.4572)
		(drill 0.254)
		(layers "F.Cu" "B.Cu")
		(net "GND")
	)
	(via
		(at 159.918146 -298.466764)
		(size 0.4572)
		(drill 0.2032)
		(layers "F.Cu" "B.Cu")
		(net "GND")
	)
	(via
		(at 315.938408 -407.00452)
		(size 0.4064)
		(drill 0.2032)
		(layers "F.Cu" "B.Cu")
		(net "GND")
	)
	(via
		(at 270.063214 -279.766776)
		(size 0.4572)
		(drill 0.2032)
		(layers "F.Cu" "B.Cu")
		(net "GND")
	)
	(via
		(at 28.433014 -305.266598)
		(size 0.4572)
		(drill 0.2032)
		(layers "F.Cu" "B.Cu")
		(net "GND")
	)
	(via
		(at 197.637146 -251.716794)
		(size 0.4572)
		(drill 0.2032)
		(layers "F.Cu" "B.Cu")
		(net "GND")
	)
	(via
		(at 342.303862 -274.266914)
		(size 0.4572)
		(drill 0.2032)
		(layers "F.Cu" "B.Cu")
		(net "GND")
	)
	(via
		(at 119.268748 -281.59202)
		(size 0.4572)
		(drill 0.2032)
		(layers "F.Cu" "B.Cu")
		(net "GND")
	)
	(via
		(at 407.984198 -403.249892)
		(size 0.4572)
		(drill 0.254)
		(layers "F.Cu" "B.Cu")
		(net "GND")
	)
	(via
		(at 353.396804 -257.692906)
		(size 0.4572)
		(drill 0.2032)
		(layers "F.Cu" "B.Cu")
		(net "GND")
	)
	(via
		(at 11.135614 -228.766624)
		(size 0.4572)
		(drill 0.2032)
		(layers "F.Cu" "B.Cu")
		(net "GND")
	)
	(via
		(at 20.889214 -284.866588)
		(size 0.4572)
		(drill 0.2032)
		(layers "F.Cu" "B.Cu")
		(net "GND")
	)
	(via
		(at 317.29426 -403.249892)
		(size 0.4572)
		(drill 0.254)
		(layers "F.Cu" "B.Cu")
		(net "GND")
	)
	(via
		(at 462.555082 -219.41663)
		(size 0.4572)
		(drill 0.2032)
		(layers "F.Cu" "B.Cu")
		(net "GND")
	)
	(via
		(at 51.064414 -194.766692)
		(size 0.4572)
		(drill 0.2032)
		(layers "F.Cu" "B.Cu")
		(net "GND")
	)
	(via
		(at 157.479746 -272.116804)
		(size 0.4572)
		(drill 0.2032)
		(layers "F.Cu" "B.Cu")
		(net "GND")
	)
	(via
		(at 365.321342 -424.460162)
		(size 0.508)
		(drill 0.254)
		(layers "F.Cu" "B.Cu")
		(net "GND")
	)
	(via
		(at 346.250006 -439.651394)
		(size 0.4572)
		(drill 0.2032)
		(layers "F.Cu" "B.Cu")
		(net "GND")
	)
	(via
		(at 84.250022 -433.899564)
		(size 0.4572)
		(drill 0.2032)
		(layers "F.Cu" "B.Cu")
		(net "GND")
	)
	(via
		(at 31.876746 -265.316716)
		(size 0.4572)
		(drill 0.2032)
		(layers "F.Cu" "B.Cu")
		(net "GND")
	)
	(via
		(at 428.71644 -358.795066)
		(size 0.508)
		(drill 0.254)
		(layers "F.Cu" "B.Cu")
		(net "GND")
	)
	(via
		(at 113.629948 -253.91999)
		(size 0.4572)
		(drill 0.2032)
		(layers "F.Cu" "B.Cu")
		(net "GND")
	)
	(via
		(at 37.210746 -251.716794)
		(size 0.4572)
		(drill 0.2032)
		(layers "F.Cu" "B.Cu")
		(net "GND")
	)
	(via
		(at 272.273014 -217.716608)
		(size 0.4572)
		(drill 0.2032)
		(layers "F.Cu" "B.Cu")
		(net "GND")
	)
	(via
		(at 435.823614 -197.316598)
		(size 0.4572)
		(drill 0.2032)
		(layers "F.Cu" "B.Cu")
		(net "GND")
	)
	(via
		(at 287.360614 -223.666558)
		(size 0.4572)
		(drill 0.2032)
		(layers "F.Cu" "B.Cu")
		(net "GND")
	)
	(via
		(at 409.349956 -432.451256)
		(size 0.4572)
		(drill 0.2032)
		(layers "F.Cu" "B.Cu")
		(net "GND")
	)
	(via
		(at 201.737214 -316.316614)
		(size 0.4572)
		(drill 0.2032)
		(layers "F.Cu" "B.Cu")
		(net "GND")
	)
	(via
		(at 254.975614 -248.31675)
		(size 0.4572)
		(drill 0.2032)
		(layers "F.Cu" "B.Cu")
		(net "GND")
	)
	(via
		(at 62.051946 -201.56678)
		(size 0.4572)
		(drill 0.2032)
		(layers "F.Cu" "B.Cu")
		(net "GND")
	)
	(via
		(at 387.774434 -226.017328)
		(size 0.4572)
		(drill 0.2032)
		(layers "F.Cu" "B.Cu")
		(net "GND")
	)
	(via
		(at 405.648414 -242.3668)
		(size 0.4572)
		(drill 0.2032)
		(layers "F.Cu" "B.Cu")
		(net "GND")
	)
	(via
		(at 365.329216 -281.59202)
		(size 0.4572)
		(drill 0.2032)
		(layers "F.Cu" "B.Cu")
		(net "GND")
	)
	(via
		(at 296.794682 -245.76659)
		(size 0.4572)
		(drill 0.2032)
		(layers "F.Cu" "B.Cu")
		(net "GND")
	)
	(via
		(at 264.729214 -295.06672)
		(size 0.4572)
		(drill 0.2032)
		(layers "F.Cu" "B.Cu")
		(net "GND")
	)
	(via
		(at 85.526118 -410.030168)
		(size 0.4064)
		(drill 0.2032)
		(layers "F.Cu" "B.Cu")
		(net "GND")
	)
	(via
		(at 155.67533 -441.225432)
		(size 0.508)
		(drill 0.254)
		(layers "F.Cu" "B.Cu")
		(net "GND")
	)
	(via
		(at 50.38725 -410.664152)
		(size 0.4572)
		(drill 0.254)
		(layers "F.Cu" "B.Cu")
		(net "GND")
	)
	(via
		(at 370.497862 -269.38351)
		(size 0.4572)
		(drill 0.2032)
		(layers "F.Cu" "B.Cu")
		(net "GND")
	)
	(via
		(at 16.789146 -260.21665)
		(size 0.4572)
		(drill 0.2032)
		(layers "F.Cu" "B.Cu")
		(net "GND")
	)
	(via
		(at 431.662078 -365.55299)
		(size 0.49022)
		(drill 0.254)
		(layers "F.Cu" "B.Cu")
		(net "GND")
	)
	(via
		(at 199.527414 -272.966688)
		(size 0.4572)
		(drill 0.2032)
		(layers "F.Cu" "B.Cu")
		(net "GND")
	)
	(via
		(at 304.338482 -247.466612)
		(size 0.4572)
		(drill 0.2032)
		(layers "F.Cu" "B.Cu")
		(net "GND")
	)
	(via
		(at 172.795946 -240.666778)
		(size 0.4572)
		(drill 0.2032)
		(layers "F.Cu" "B.Cu")
		(net "GND")
	)
	(via
		(at 294.904414 -234.716574)
		(size 0.4572)
		(drill 0.2032)
		(layers "F.Cu" "B.Cu")
		(net "GND")
	)
	(via
		(at 460.664814 -251.716794)
		(size 0.4572)
		(drill 0.2032)
		(layers "F.Cu" "B.Cu")
		(net "GND")
	)
	(via
		(at 56.398414 -264.466578)
		(size 0.4572)
		(drill 0.2032)
		(layers "F.Cu" "B.Cu")
		(net "GND")
	)
	(via
		(at 299.004482 -289.966654)
		(size 0.4572)
		(drill 0.2032)
		(layers "F.Cu" "B.Cu")
		(net "GND")
	)
	(via
		(at 7.035546 -197.316598)
		(size 0.4572)
		(drill 0.2032)
		(layers "F.Cu" "B.Cu")
		(net "GND")
	)
	(via
		(at 59.842146 -197.316598)
		(size 0.4572)
		(drill 0.2032)
		(layers "F.Cu" "B.Cu")
		(net "GND")
	)
	(via
		(at 31.876746 -292.516814)
		(size 0.4572)
		(drill 0.2032)
		(layers "F.Cu" "B.Cu")
		(net "GND")
	)
	(via
		(at 46.553882 -351.888298)
		(size 0.508)
		(drill 0.254)
		(layers "F.Cu" "B.Cu")
		(net "GND")
	)
	(via
		(at 352.171762 -289.807142)
		(size 0.4572)
		(drill 0.2032)
		(layers "F.Cu" "B.Cu")
		(net "GND")
	)
	(via
		(at 294.904414 -311.216802)
		(size 0.4572)
		(drill 0.2032)
		(layers "F.Cu" "B.Cu")
		(net "GND")
	)
	(via
		(at 379.316234 -219.506038)
		(size 0.4572)
		(drill 0.2032)
		(layers "F.Cu" "B.Cu")
		(net "GND")
	)
	(via
		(at 346.20962 -409.396184)
		(size 0.4572)
		(drill 0.254)
		(layers "F.Cu" "B.Cu")
		(net "GND")
	)
	(via
		(at 311.882282 -280.61666)
		(size 0.4572)
		(drill 0.2032)
		(layers "F.Cu" "B.Cu")
		(net "GND")
	)
	(via
		(at 436.409846 -380.05258)
		(size 0.508)
		(drill 0.254)
		(layers "F.Cu" "B.Cu")
		(net "GND")
	)
	(via
		(at 52.298346 -203.266802)
		(size 0.4572)
		(drill 0.2032)
		(layers "F.Cu" "B.Cu")
		(net "GND")
	)
	(via
		(at 135.714994 -280.778204)
		(size 0.4572)
		(drill 0.2032)
		(layers "F.Cu" "B.Cu")
		(net "GND")
	)
	(via
		(at 435.823614 -272.116804)
		(size 0.4572)
		(drill 0.2032)
		(layers "F.Cu" "B.Cu")
		(net "GND")
	)
	(via
		(at 134.815326 -410.664152)
		(size 0.4572)
		(drill 0.254)
		(layers "F.Cu" "B.Cu")
		(net "GND")
	)
	(via
		(at 199.527414 -262.76681)
		(size 0.4572)
		(drill 0.2032)
		(layers "F.Cu" "B.Cu")
		(net "GND")
	)
	(via
		(at 7.035546 -287.416748)
		(size 0.4572)
		(drill 0.2032)
		(layers "F.Cu" "B.Cu")
		(net "GND")
	)
	(via
		(at 28.433014 -264.466578)
		(size 0.4572)
		(drill 0.2032)
		(layers "F.Cu" "B.Cu")
		(net "GND")
	)
	(via
		(at 9.20877 -77.462888)
		(size 0.508)
		(drill 0.254)
		(layers "F.Cu" "B.Cu")
		(net "GND")
	)
	(via
		(at 107.520994 -284.033722)
		(size 0.4572)
		(drill 0.2032)
		(layers "F.Cu" "B.Cu")
		(net "GND")
	)
	(via
		(at 310.116474 -320.063622)
		(size 0.4572)
		(drill 0.2032)
		(layers "F.Cu" "B.Cu")
		(net "GND")
	)
	(via
		(at 317.250064 -439.651394)
		(size 0.4572)
		(drill 0.2032)
		(layers "F.Cu" "B.Cu")
		(net "GND")
	)
	(via
		(at 161.808414 -262.76681)
		(size 0.4572)
		(drill 0.2032)
		(layers "F.Cu" "B.Cu")
		(net "GND")
	)
	(via
		(at 209.281014 -314.616592)
		(size 0.4572)
		(drill 0.2032)
		(layers "F.Cu" "B.Cu")
		(net "GND")
	)
	(via
		(at 399.349976 -437.49976)
		(size 0.4572)
		(drill 0.2032)
		(layers "F.Cu" "B.Cu")
		(net "GND")
	)
	(via
		(at 307.566314 -206.666592)
		(size 0.4572)
		(drill 0.2032)
		(layers "F.Cu" "B.Cu")
		(net "GND")
	)
	(via
		(at 118.433088 -254.01524)
		(size 0.4572)
		(drill 0.2032)
		(layers "F.Cu" "B.Cu")
		(net "GND")
	)
	(via
		(at 212.724746 -199.01662)
		(size 0.4572)
		(drill 0.2032)
		(layers "F.Cu" "B.Cu")
		(net "GND")
	)
	(via
		(at 58.233056 -161.572702)
		(size 0.508)
		(drill 0.254)
		(layers "F.Cu" "B.Cu")
		(net "GND")
	)
	(via
		(at 326.64527 -341.063072)
		(size 0.49022)
		(drill 0.254)
		(layers "F.Cu" "B.Cu")
		(net "GND")
	)
	(via
		(at 338.250022 -430.147222)
		(size 0.4572)
		(drill 0.2032)
		(layers "F.Cu" "B.Cu")
		(net "GND")
	)
	(via
		(at 95.193866 -217.064336)
		(size 0.4572)
		(drill 0.2032)
		(layers "F.Cu" "B.Cu")
		(net "GND")
	)
	(via
		(at 7.035546 -229.616762)
		(size 0.4572)
		(drill 0.2032)
		(layers "F.Cu" "B.Cu")
		(net "GND")
	)
	(via
		(at 304.338482 -211.766658)
		(size 0.4572)
		(drill 0.2032)
		(layers "F.Cu" "B.Cu")
		(net "GND")
	)
	(via
		(at 458.455014 -279.766776)
		(size 0.4572)
		(drill 0.2032)
		(layers "F.Cu" "B.Cu")
		(net "GND")
	)
	(via
		(at 293.614856 -365.979456)
		(size 0.508)
		(drill 0.254)
		(layers "F.Cu" "B.Cu")
		(net "GND")
	)
	(via
		(at 271.962372 -69.5198)
		(size 0.508)
		(drill 0.254)
		(layers "F.Cu" "B.Cu")
		(net "GND")
	)
	(via
		(at 122.557794 -269.38351)
		(size 0.4572)
		(drill 0.2032)
		(layers "F.Cu" "B.Cu")
		(net "GND")
	)
	(via
		(at 329.634596 -409.396184)
		(size 0.4572)
		(drill 0.254)
		(layers "F.Cu" "B.Cu")
		(net "GND")
	)
	(via
		(at 378.486416 -279.964134)
		(size 0.4572)
		(drill 0.2032)
		(layers "F.Cu" "B.Cu")
		(net "GND")
	)
	(via
		(at 14.579346 -300.166786)
		(size 0.4572)
		(drill 0.2032)
		(layers "F.Cu" "B.Cu")
		(net "GND")
	)
	(via
		(at 180.955696 -114.17554)
		(size 0.4572)
		(drill 0.254)
		(layers "F.Cu" "B.Cu")
		(net "GND")
	)
	(via
		(at 102.53345 -92.222574)
		(size 0.508)
		(drill 0.254)
		(layers "F.Cu" "B.Cu")
		(net "GND")
	)
	(via
		(at 157.349952 -430.147222)
		(size 0.4572)
		(drill 0.2032)
		(layers "F.Cu" "B.Cu")
		(net "GND")
	)
	(via
		(at 285.150814 -272.116804)
		(size 0.4572)
		(drill 0.2032)
		(layers "F.Cu" "B.Cu")
		(net "GND")
	)
	(via
		(at 315.674248 -400.858228)
		(size 0.4064)
		(drill 0.2032)
		(layers "F.Cu" "B.Cu")
		(net "GND")
	)
	(via
		(at 87.785194 -287.28924)
		(size 0.4572)
		(drill 0.2032)
		(layers "F.Cu" "B.Cu")
		(net "GND")
	)
	(via
		(at 57.684924 -177.327052)
		(size 0.508)
		(drill 0.254)
		(layers "F.Cu" "B.Cu")
		(net "GND")
	)
	(via
		(at 37.210746 -313.766708)
		(size 0.4572)
		(drill 0.2032)
		(layers "F.Cu" "B.Cu")
		(net "GND")
	)
	(via
		(at 101.412294 -268.569694)
		(size 0.4572)
		(drill 0.2032)
		(layers "F.Cu" "B.Cu")
		(net "GND")
	)
	(via
		(at 314.092082 -303.566576)
		(size 0.4572)
		(drill 0.2032)
		(layers "F.Cu" "B.Cu")
		(net "GND")
	)
	(via
		(at 210.514946 -238.966756)
		(size 0.4572)
		(drill 0.2032)
		(layers "F.Cu" "B.Cu")
		(net "GND")
	)
	(via
		(at 209.281014 -200.716642)
		(size 0.4572)
		(drill 0.2032)
		(layers "F.Cu" "B.Cu")
		(net "GND")
	)
	(via
		(at 370.51488 -46.192948)
		(size 0.508)
		(drill 0.254)
		(layers "F.Cu" "B.Cu")
		(net "GND")
	)
	(via
		(at 413.336486 -165.727126)
		(size 0.508)
		(drill 0.254)
		(layers "F.Cu" "B.Cu")
		(net "GND")
	)
	(via
		(at 90.964766 -239.0394)
		(size 0.4572)
		(drill 0.2032)
		(layers "F.Cu" "B.Cu")
		(net "GND")
	)
	(via
		(at 381.195834 -226.017328)
		(size 0.4572)
		(drill 0.2032)
		(layers "F.Cu" "B.Cu")
		(net "GND")
	)
	(via
		(at 259.075682 -235.566712)
		(size 0.4572)
		(drill 0.2032)
		(layers "F.Cu" "B.Cu")
		(net "GND")
	)
	(via
		(at 344.07348 -246.364506)
		(size 0.4572)
		(drill 0.2032)
		(layers "F.Cu" "B.Cu")
		(net "GND")
	)
	(via
		(at 51.572922 -174.366682)
		(size 0.49022)
		(drill 0.254)
		(layers "F.Cu" "B.Cu")
		(net "GND")
	)
	(via
		(at 82.86623 -340.981792)
		(size 0.49022)
		(drill 0.254)
		(layers "F.Cu" "B.Cu")
		(net "GND")
	)
	(via
		(at 370.967762 -286.475424)
		(size 0.4572)
		(drill 0.2032)
		(layers "F.Cu" "B.Cu")
		(net "GND")
	)
	(via
		(at 449.677282 -305.266598)
		(size 0.4572)
		(drill 0.2032)
		(layers "F.Cu" "B.Cu")
		(net "GND")
	)
	(via
		(at 86.250018 -438.499758)
		(size 0.4572)
		(drill 0.2032)
		(layers "F.Cu" "B.Cu")
		(net "GND")
	)
	(via
		(at 383.185162 -260.430772)
		(size 0.4572)
		(drill 0.2032)
		(layers "F.Cu" "B.Cu")
		(net "GND")
	)
	(via
		(at 197.637146 -234.716574)
		(size 0.4572)
		(drill 0.2032)
		(layers "F.Cu" "B.Cu")
		(net "GND")
	)
	(via
		(at 171.562014 -280.61666)
		(size 0.4572)
		(drill 0.2032)
		(layers "F.Cu" "B.Cu")
		(net "GND")
	)
	(via
		(at 48.854614 -289.966654)
		(size 0.4572)
		(drill 0.2032)
		(layers "F.Cu" "B.Cu")
		(net "GND")
	)
	(via
		(at 63.942214 -221.116652)
		(size 0.4572)
		(drill 0.2032)
		(layers "F.Cu" "B.Cu")
		(net "GND")
	)
	(via
		(at 52.298346 -290.816792)
		(size 0.4572)
		(drill 0.2032)
		(layers "F.Cu" "B.Cu")
		(net "GND")
	)
	(via
		(at 337.49488 -225.203258)
		(size 0.4572)
		(drill 0.2032)
		(layers "F.Cu" "B.Cu")
		(net "GND")
	)
	(via
		(at 460.664814 -285.716726)
		(size 0.4572)
		(drill 0.2032)
		(layers "F.Cu" "B.Cu")
		(net "GND")
	)
	(via
		(at 35.976814 -235.566712)
		(size 0.4572)
		(drill 0.2032)
		(layers "F.Cu" "B.Cu")
		(net "GND")
	)
	(via
		(at 370.497862 -259.616956)
		(size 0.4572)
		(drill 0.2032)
		(layers "F.Cu" "B.Cu")
		(net "GND")
	)
	(via
		(at 176.896014 -239.81664)
		(size 0.4572)
		(drill 0.2032)
		(layers "F.Cu" "B.Cu")
		(net "GND")
	)
	(via
		(at 358.280462 -275.8948)
		(size 0.4572)
		(drill 0.2032)
		(layers "F.Cu" "B.Cu")
		(net "GND")
	)
	(via
		(at 382.35001 -437.49976)
		(size 0.4572)
		(drill 0.2032)
		(layers "F.Cu" "B.Cu")
		(net "GND")
	)
	(via
		(at 71.73468 -63.157608)
		(size 0.508)
		(drill 0.254)
		(layers "F.Cu" "B.Cu")
		(net "GND")
	)
	(via
		(at 442.171074 -124.297948)
		(size 0.508)
		(drill 0.254)
		(layers "F.Cu" "B.Cu")
		(net "GND")
	)
	(via
		(at 413.192214 -289.11677)
		(size 0.4572)
		(drill 0.2032)
		(layers "F.Cu" "B.Cu")
		(net "GND")
	)
	(via
		(at 430.01184 -358.795066)
		(size 0.508)
		(drill 0.254)
		(layers "F.Cu" "B.Cu")
		(net "GND")
	)
	(via
		(at 261.285482 -258.516628)
		(size 0.4572)
		(drill 0.2032)
		(layers "F.Cu" "B.Cu")
		(net "GND")
	)
	(via
		(at 9.258046 -319.344548)
		(size 0.4572)
		(drill 0.2032)
		(layers "F.Cu" "B.Cu")
		(net "GND")
	)
	(via
		(at 338.90458 -235.783882)
		(size 0.4572)
		(drill 0.2032)
		(layers "F.Cu" "B.Cu")
		(net "GND")
	)
	(via
		(at 115.716304 -357.91775)
		(size 0.508)
		(drill 0.254)
		(layers "F.Cu" "B.Cu")
		(net "GND")
	)
	(via
		(at 268.829282 -294.216582)
		(size 0.4572)
		(drill 0.2032)
		(layers "F.Cu" "B.Cu")
		(net "GND")
	)
	(via
		(at 176.896014 -299.316648)
		(size 0.4572)
		(drill 0.2032)
		(layers "F.Cu" "B.Cu")
		(net "GND")
	)
	(via
		(at 63.726314 -216.866724)
		(size 0.4572)
		(drill 0.2032)
		(layers "F.Cu" "B.Cu")
		(net "GND")
	)
	(via
		(at 299.004482 -228.766624)
		(size 0.4572)
		(drill 0.2032)
		(layers "F.Cu" "B.Cu")
		(net "GND")
	)
	(via
		(at 367.568734 -213.732618)
		(size 0.4572)
		(drill 0.2032)
		(layers "F.Cu" "B.Cu")
		(net "GND")
	)
	(via
		(at 98.592894 -270.19758)
		(size 0.4572)
		(drill 0.2032)
		(layers "F.Cu" "B.Cu")
		(net "GND")
	)
	(via
		(at 302.664114 -234.716574)
		(size 0.4572)
		(drill 0.2032)
		(layers "F.Cu" "B.Cu")
		(net "GND")
	)
	(via
		(at 257.185922 -319.328292)
		(size 0.4572)
		(drill 0.2032)
		(layers "F.Cu" "B.Cu")
		(net "GND")
	)
	(via
		(at 382.245362 -257.175254)
		(size 0.4572)
		(drill 0.2032)
		(layers "F.Cu" "B.Cu")
		(net "GND")
	)
	(via
		(at 62.267846 -220.266768)
		(size 0.4572)
		(drill 0.2032)
		(layers "F.Cu" "B.Cu")
		(net "GND")
	)
	(via
		(at 89.664794 -288.917126)
		(size 0.4572)
		(drill 0.2032)
		(layers "F.Cu" "B.Cu")
		(net "GND")
	)
	(via
		(at 94.985078 -332.56601)
		(size 0.49022)
		(drill 0.254)
		(layers "F.Cu" "B.Cu")
		(net "GND")
	)
	(via
		(at 335.255362 -263.686544)
		(size 0.4318)
		(drill 0.2032)
		(layers "F.Cu" "B.Cu")
		(net "GND")
	)
	(via
		(at 119.130826 -326.826372)
		(size 0.508)
		(drill 0.254)
		(layers "F.Cu" "B.Cu")
		(net "GND")
	)
	(via
		(at 360.51998 -216.25052)
		(size 0.4572)
		(drill 0.2032)
		(layers "F.Cu" "B.Cu")
		(net "GND")
	)
	(via
		(at 186.649614 -232.166668)
		(size 0.4572)
		(drill 0.2032)
		(layers "F.Cu" "B.Cu")
		(net "GND")
	)
	(via
		(at 110.340394 -274.266914)
		(size 0.4572)
		(drill 0.2032)
		(layers "F.Cu" "B.Cu")
		(net "GND")
	)
	(via
		(at 157.708346 -278.066754)
		(size 0.4572)
		(drill 0.2032)
		(layers "F.Cu" "B.Cu")
		(net "GND")
	)
	(via
		(at 25.215596 -387.608826)
		(size 0.508)
		(drill 0.254)
		(layers "F.Cu" "B.Cu")
		(net "GND")
	)
	(via
		(at 181.407308 -48.22571)
		(size 0.508)
		(drill 0.254)
		(layers "F.Cu" "B.Cu")
		(net "GND")
	)
	(via
		(at 145.448274 -410.030168)
		(size 0.4064)
		(drill 0.2032)
		(layers "F.Cu" "B.Cu")
		(net "GND")
	)
	(via
		(at 403.116542 -401.492212)
		(size 0.4572)
		(drill 0.254)
		(layers "F.Cu" "B.Cu")
		(net "GND")
	)
	(via
		(at 2.764536 -218.870022)
		(size 0.508)
		(drill 0.254)
		(layers "F.Cu" "B.Cu")
		(net "GND")
	)
	(via
		(at 283.916882 -244.066568)
		(size 0.4572)
		(drill 0.2032)
		(layers "F.Cu" "B.Cu")
		(net "GND")
	)
	(via
		(at 175.005746 -272.116804)
		(size 0.4572)
		(drill 0.2032)
		(layers "F.Cu" "B.Cu")
		(net "GND")
	)
	(via
		(at 20.889214 -258.516628)
		(size 0.4572)
		(drill 0.2032)
		(layers "F.Cu" "B.Cu")
		(net "GND")
	)
	(via
		(at 378.84608 -228.45903)
		(size 0.4572)
		(drill 0.2032)
		(layers "F.Cu" "B.Cu")
		(net "GND")
	)
	(via
		(at 376.49658 -227.64496)
		(size 0.4572)
		(drill 0.2032)
		(layers "F.Cu" "B.Cu")
		(net "GND")
	)
	(via
		(at 114.660934 -109.106462)
		(size 0.508)
		(drill 0.254)
		(layers "F.Cu" "B.Cu")
		(net "GND")
	)
	(via
		(at 197.637146 -214.316564)
		(size 0.4572)
		(drill 0.2032)
		(layers "F.Cu" "B.Cu")
		(net "GND")
	)
	(via
		(at 412.172404 -288.317432)
		(size 0.4572)
		(drill 0.2032)
		(layers "F.Cu" "B.Cu")
		(net "GND")
	)
	(via
		(at 389.864346 -78.853538)
		(size 0.508)
		(drill 0.254)
		(layers "F.Cu" "B.Cu")
		(net "GND")
	)
	(via
		(at 110.340394 -271.011396)
		(size 0.4572)
		(drill 0.2032)
		(layers "F.Cu" "B.Cu")
		(net "GND")
	)
	(via
		(at 405.648414 -265.316716)
		(size 0.4572)
		(drill 0.2032)
		(layers "F.Cu" "B.Cu")
		(net "GND")
	)
	(via
		(at 348.287848 -400.834352)
		(size 0.4064)
		(drill 0.2032)
		(layers "F.Cu" "B.Cu")
		(net "GND")
	)
	(via
		(at 18.679414 -305.266598)
		(size 0.4572)
		(drill 0.2032)
		(layers "F.Cu" "B.Cu")
		(net "GND")
	)
	(via
		(at 79.186532 -32.377126)
		(size 0.508)
		(drill 0.254)
		(layers "F.Cu" "B.Cu")
		(net "GND")
	)
	(via
		(at 341.25408 -244.73662)
		(size 0.4572)
		(drill 0.2032)
		(layers "F.Cu" "B.Cu")
		(net "GND")
	)
	(via
		(at 39.420546 -221.96679)
		(size 0.4572)
		(drill 0.2032)
		(layers "F.Cu" "B.Cu")
		(net "GND")
	)
	(via
		(at 340.894416 -258.80314)
		(size 0.4572)
		(drill 0.2032)
		(layers "F.Cu" "B.Cu")
		(net "GND")
	)
	(via
		(at 172.795946 -317.166752)
		(size 0.4572)
		(drill 0.2032)
		(layers "F.Cu" "B.Cu")
		(net "GND")
	)
	(via
		(at 363.656118 -357.91775)
		(size 0.508)
		(drill 0.254)
		(layers "F.Cu" "B.Cu")
		(net "GND")
	)
	(via
		(at 323.508116 -410.664152)
		(size 0.4572)
		(drill 0.254)
		(layers "F.Cu" "B.Cu")
		(net "GND")
	)
	(via
		(at 63.250064 -427.851316)
		(size 0.4572)
		(drill 0.2032)
		(layers "F.Cu" "B.Cu")
		(net "GND")
	)
	(via
		(at 190.093346 -260.21665)
		(size 0.4572)
		(drill 0.2032)
		(layers "F.Cu" "B.Cu")
		(net "GND")
	)
	(via
		(at 244.73408 -168.925748)
		(size 0.508)
		(drill 0.254)
		(layers "F.Cu" "B.Cu")
		(net "GND")
	)
	(via
		(at 315.60008 -42.001948)
		(size 0.508)
		(drill 0.254)
		(layers "F.Cu" "B.Cu")
		(net "GND")
	)
	(via
		(at 399.77949 -410.030168)
		(size 0.4064)
		(drill 0.2032)
		(layers "F.Cu" "B.Cu")
		(net "GND")
	)
	(via
		(at 161.808414 -286.74441)
		(size 0.4572)
		(drill 0.2032)
		(layers "F.Cu" "B.Cu")
		(net "GND")
	)
	(via
		(at 417.292282 -305.266598)
		(size 0.4572)
		(drill 0.2032)
		(layers "F.Cu" "B.Cu")
		(net "GND")
	)
	(via
		(at 376.606816 -270.19758)
		(size 0.4572)
		(drill 0.2032)
		(layers "F.Cu" "B.Cu")
		(net "GND")
	)
	(via
		(at 161.808414 -247.466612)
		(size 0.4572)
		(drill 0.2032)
		(layers "F.Cu" "B.Cu")
		(net "GND")
	)
	(via
		(at 370.620544 -366.329214)
		(size 0.508)
		(drill 0.254)
		(layers "F.Cu" "B.Cu")
		(net "GND")
	)
	(via
		(at 419.802818 -210.066636)
		(size 0.4572)
		(drill 0.2032)
		(layers "F.Cu" "B.Cu")
		(net "GND")
	)
	(via
		(at 44.754546 -210.916774)
		(size 0.4572)
		(drill 0.2032)
		(layers "F.Cu" "B.Cu")
		(net "GND")
	)
	(via
		(at 377.28652 -358.699308)
		(size 0.508)
		(drill 0.254)
		(layers "F.Cu" "B.Cu")
		(net "GND")
	)
	(via
		(at 292.694614 -258.516628)
		(size 0.4572)
		(drill 0.2032)
		(layers "F.Cu" "B.Cu")
		(net "GND")
	)
	(via
		(at 431.36693 -12.37488)
		(size 0.508)
		(drill 0.254)
		(layers "F.Cu" "B.Cu")
		(net "GND")
	)
	(via
		(at 405.648414 -251.716794)
		(size 0.4572)
		(drill 0.2032)
		(layers "F.Cu" "B.Cu")
		(net "GND")
	)
	(via
		(at 176.896014 -280.61666)
		(size 0.4572)
		(drill 0.2032)
		(layers "F.Cu" "B.Cu")
		(net "GND")
	)
	(via
		(at 449.5546 -9.583928)
		(size 0.508)
		(drill 0.254)
		(layers "F.Cu" "B.Cu")
		(net "GND")
	)
	(via
		(at 350.65208 -233.34218)
		(size 0.4572)
		(drill 0.2032)
		(layers "F.Cu" "B.Cu")
		(net "GND")
	)
	(via
		(at 350.716088 -410.030168)
		(size 0.4064)
		(drill 0.2032)
		(layers "F.Cu" "B.Cu")
		(net "GND")
	)
	(via
		(at 374.617234 -226.017328)
		(size 0.4572)
		(drill 0.2032)
		(layers "F.Cu" "B.Cu")
		(net "GND")
	)
	(via
		(at 147.068286 -409.396184)
		(size 0.4572)
		(drill 0.254)
		(layers "F.Cu" "B.Cu")
		(net "GND")
	)
	(via
		(at 31.876746 -287.416748)
		(size 0.4572)
		(drill 0.2032)
		(layers "F.Cu" "B.Cu")
		(net "GND")
	)
	(via
		(at 434.589682 -232.166668)
		(size 0.4572)
		(drill 0.2032)
		(layers "F.Cu" "B.Cu")
		(net "GND")
	)
	(via
		(at 16.789146 -307.816758)
		(size 0.4572)
		(drill 0.2032)
		(layers "F.Cu" "B.Cu")
		(net "GND")
	)
	(via
		(at 113.629948 -257.175508)
		(size 0.4572)
		(drill 0.2032)
		(layers "F.Cu" "B.Cu")
		(net "GND")
	)
	(via
		(at 225.135948 -135.73252)
		(size 0.508)
		(drill 0.254)
		(layers "F.Cu" "B.Cu")
		(net "GND")
	)
	(via
		(at 45.179234 -107.031282)
		(size 0.508)
		(drill 0.254)
		(layers "F.Cu" "B.Cu")
		(net "GND")
	)
	(via
		(at 380.835662 -259.616956)
		(size 0.4572)
		(drill 0.2032)
		(layers "F.Cu" "B.Cu")
		(net "GND")
	)
	(via
		(at 94.254066 -241.481102)
		(size 0.4572)
		(drill 0.2032)
		(layers "F.Cu" "B.Cu")
		(net "GND")
	)
	(via
		(at 363.363256 -241.081052)
		(size 0.4572)
		(drill 0.2032)
		(layers "F.Cu" "B.Cu")
		(net "GND")
	)
	(via
		(at 59.842146 -292.516814)
		(size 0.4572)
		(drill 0.2032)
		(layers "F.Cu" "B.Cu")
		(net "GND")
	)
	(via
		(at 355.821234 -229.272846)
		(size 0.4572)
		(drill 0.2032)
		(layers "F.Cu" "B.Cu")
		(net "GND")
	)
	(via
		(at 17.10309 -17.61236)
		(size 0.508)
		(drill 0.254)
		(layers "F.Cu" "B.Cu")
		(net "GND")
	)
	(via
		(at 362.399834 -226.017328)
		(size 0.4572)
		(drill 0.2032)
		(layers "F.Cu" "B.Cu")
		(net "GND")
	)
	(via
		(at 285.150814 -304.416714)
		(size 0.4572)
		(drill 0.2032)
		(layers "F.Cu" "B.Cu")
		(net "GND")
	)
	(via
		(at 117.279166 -226.017328)
		(size 0.4572)
		(drill 0.2032)
		(layers "F.Cu" "B.Cu")
		(net "GND")
	)
	(via
		(at 274.163282 -211.766658)
		(size 0.4572)
		(drill 0.2032)
		(layers "F.Cu" "B.Cu")
		(net "GND")
	)
	(via
		(at 87.14613 -407.638504)
		(size 0.4572)
		(drill 0.254)
		(layers "F.Cu" "B.Cu")
		(net "GND")
	)
	(via
		(at 345.317064 -338.850732)
		(size 0.508)
		(drill 0.254)
		(layers "F.Cu" "B.Cu")
		(net "GND")
	)
	(via
		(at 459.1939 -387.30682)
		(size 0.508)
		(drill 0.254)
		(layers "F.Cu" "B.Cu")
		(net "GND")
	)
	(via
		(at 435.823614 -201.56678)
		(size 0.4572)
		(drill 0.2032)
		(layers "F.Cu" "B.Cu")
		(net "GND")
	)
	(via
		(at 348.882462 -282.405836)
		(size 0.4572)
		(drill 0.2032)
		(layers "F.Cu" "B.Cu")
		(net "GND")
	)
	(via
		(at 79.399638 -410.030168)
		(size 0.4064)
		(drill 0.2032)
		(layers "F.Cu" "B.Cu")
		(net "GND")
	)
	(via
		(at 124.437394 -272.639282)
		(size 0.4572)
		(drill 0.2032)
		(layers "F.Cu" "B.Cu")
		(net "GND")
	)
	(via
		(at 39.420546 -233.016806)
		(size 0.4572)
		(drill 0.2032)
		(layers "F.Cu" "B.Cu")
		(net "GND")
	)
	(via
		(at 401.785328 -6.07949)
		(size 0.508)
		(drill 0.254)
		(layers "F.Cu" "B.Cu")
		(net "GND")
	)
	(via
		(at 259.075682 -219.41663)
		(size 0.4572)
		(drill 0.2032)
		(layers "F.Cu" "B.Cu")
		(net "GND")
	)
	(via
		(at 115.039394 -279.150318)
		(size 0.4572)
		(drill 0.2032)
		(layers "F.Cu" "B.Cu")
		(net "GND")
	)
	(via
		(at 351.26168 -186.36615)
		(size 0.508)
		(drill 0.254)
		(layers "F.Cu" "B.Cu")
		(net "GND")
	)
	(via
		(at 133.346952 -17.655032)
		(size 0.508)
		(drill 0.254)
		(layers "F.Cu" "B.Cu")
		(net "GND")
	)
	(via
		(at 289.250882 -301.01667)
		(size 0.4572)
		(drill 0.2032)
		(layers "F.Cu" "B.Cu")
		(net "GND")
	)
	(via
		(at 13.345414 -221.116652)
		(size 0.4572)
		(drill 0.2032)
		(layers "F.Cu" "B.Cu")
		(net "GND")
	)
	(via
		(at 175.005746 -227.066602)
		(size 0.4572)
		(drill 0.2032)
		(layers "F.Cu" "B.Cu")
		(net "GND")
	)
	(via
		(at 39.319962 -433.967128)
		(size 0.508)
		(drill 0.254)
		(layers "F.Cu" "B.Cu")
		(net "GND")
	)
	(via
		(at 356.400862 -271.011396)
		(size 0.4572)
		(drill 0.2032)
		(layers "F.Cu" "B.Cu")
		(net "GND")
	)
	(via
		(at 101.302566 -230.900478)
		(size 0.4572)
		(drill 0.2032)
		(layers "F.Cu" "B.Cu")
		(net "GND")
	)
	(via
		(at 309.992014 -225.36658)
		(size 0.4572)
		(drill 0.2032)
		(layers "F.Cu" "B.Cu")
		(net "GND")
	)
	(via
		(at 427.045882 -301.01667)
		(size 0.4572)
		(drill 0.2032)
		(layers "F.Cu" "B.Cu")
		(net "GND")
	)
	(via
		(at 82.824066 -406.370536)
		(size 0.4572)
		(drill 0.254)
		(layers "F.Cu" "B.Cu")
		(net "GND")
	)
	(via
		(at 59.626246 -311.216802)
		(size 0.4572)
		(drill 0.2032)
		(layers "F.Cu" "B.Cu")
		(net "GND")
	)
	(via
		(at 20.889214 -210.066636)
		(size 0.4572)
		(drill 0.2032)
		(layers "F.Cu" "B.Cu")
		(net "GND")
	)
	(via
		(at 98.013012 -241.481102)
		(size 0.4572)
		(drill 0.2032)
		(layers "F.Cu" "B.Cu")
		(net "GND")
	)
	(via
		(at 414.070292 -162.877754)
		(size 0.49022)
		(drill 0.254)
		(layers "F.Cu" "B.Cu")
		(net "GND")
	)
	(via
		(at 364.279434 -222.761556)
		(size 0.4572)
		(drill 0.2032)
		(layers "F.Cu" "B.Cu")
		(net "GND")
	)
	(via
		(at 161.808414 -277.216616)
		(size 0.4572)
		(drill 0.2032)
		(layers "F.Cu" "B.Cu")
		(net "GND")
	)
	(via
		(at 110.57636 -31.837884)
		(size 0.508)
		(drill 0.254)
		(layers "F.Cu" "B.Cu")
		(net "GND")
	)
	(via
		(at 252.320298 -109.176058)
		(size 0.508)
		(drill 0.254)
		(layers "F.Cu" "B.Cu")
		(net "GND")
	)
	(via
		(at 430.489614 -285.716726)
		(size 0.4572)
		(drill 0.2032)
		(layers "F.Cu" "B.Cu")
		(net "GND")
	)
	(via
		(at 91.544394 -284.033722)
		(size 0.4572)
		(drill 0.2032)
		(layers "F.Cu" "B.Cu")
		(net "GND")
	)
	(via
		(at 445.577214 -315.46673)
		(size 0.4572)
		(drill 0.2032)
		(layers "F.Cu" "B.Cu")
		(net "GND")
	)
	(via
		(at 62.267846 -273.816572)
		(size 0.4572)
		(drill 0.2032)
		(layers "F.Cu" "B.Cu")
		(net "GND")
	)
	(via
		(at 177.02276 -365.24057)
		(size 0.508)
		(drill 0.254)
		(layers "F.Cu" "B.Cu")
		(net "GND")
	)
	(via
		(at 102.90683 -240.928906)
		(size 0.4572)
		(drill 0.2032)
		(layers "F.Cu" "B.Cu")
		(net "GND")
	)
	(via
		(at 207.071214 -200.716642)
		(size 0.4572)
		(drill 0.2032)
		(layers "F.Cu" "B.Cu")
		(net "GND")
	)
	(via
		(at 86.735412 -239.853216)
		(size 0.4318)
		(drill 0.2032)
		(layers "F.Cu" "B.Cu")
		(net "GND")
	)
	(via
		(at 287.360614 -273.816572)
		(size 0.4572)
		(drill 0.2032)
		(layers "F.Cu" "B.Cu")
		(net "GND")
	)
	(via
		(at 24.332946 -276.366732)
		(size 0.4572)
		(drill 0.2032)
		(layers "F.Cu" "B.Cu")
		(net "GND")
	)
	(via
		(at 63.942214 -261.066788)
		(size 0.4572)
		(drill 0.2032)
		(layers "F.Cu" "B.Cu")
		(net "GND")
	)
	(via
		(at 13.345414 -207.51673)
		(size 0.4572)
		(drill 0.2032)
		(layers "F.Cu" "B.Cu")
		(net "GND")
	)
	(via
		(at 384.824478 -409.396184)
		(size 0.4572)
		(drill 0.254)
		(layers "F.Cu" "B.Cu")
		(net "GND")
	)
	(via
		(at 394.349986 -431.451258)
		(size 0.4572)
		(drill 0.2032)
		(layers "F.Cu" "B.Cu")
		(net "GND")
	)
	(via
		(at 392.209782 -406.34666)
		(size 0.4572)
		(drill 0.254)
		(layers "F.Cu" "B.Cu")
		(net "GND")
	)
	(via
		(at 116.449348 -286.475424)
		(size 0.4572)
		(drill 0.2032)
		(layers "F.Cu" "B.Cu")
		(net "GND")
	)
	(via
		(at 66.152014 -213.46668)
		(size 0.4572)
		(drill 0.2032)
		(layers "F.Cu" "B.Cu")
		(net "GND")
	)
	(via
		(at 184.439814 -284.866588)
		(size 0.4572)
		(drill 0.2032)
		(layers "F.Cu" "B.Cu")
		(net "GND")
	)
	(via
		(at 261.285482 -235.566712)
		(size 0.4572)
		(drill 0.2032)
		(layers "F.Cu" "B.Cu")
		(net "GND")
	)
	(via
		(at 120.678194 -282.405836)
		(size 0.4572)
		(drill 0.2032)
		(layers "F.Cu" "B.Cu")
		(net "GND")
	)
	(via
		(at 147.068286 -410.664152)
		(size 0.4572)
		(drill 0.254)
		(layers "F.Cu" "B.Cu")
		(net "GND")
	)
	(via
		(at 89.664794 -272.639282)
		(size 0.4572)
		(drill 0.2032)
		(layers "F.Cu" "B.Cu")
		(net "GND")
	)
	(via
		(at 164.19576 -11.082528)
		(size 0.508)
		(drill 0.254)
		(layers "F.Cu" "B.Cu")
		(net "GND")
	)
	(via
		(at 9.245346 -221.96679)
		(size 0.4572)
		(drill 0.2032)
		(layers "F.Cu" "B.Cu")
		(net "GND")
	)
	(via
		(at 261.285482 -250.866656)
		(size 0.4572)
		(drill 0.2032)
		(layers "F.Cu" "B.Cu")
		(net "GND")
	)
	(via
		(at 299.004482 -308.666642)
		(size 0.4572)
		(drill 0.2032)
		(layers "F.Cu" "B.Cu")
		(net "GND")
	)
	(via
		(at 407.190194 -4.317746)
		(size 0.508)
		(drill 0.254)
		(layers "F.Cu" "B.Cu")
		(net "GND")
	)
	(via
		(at 292.694614 -267.016738)
		(size 0.4572)
		(drill 0.2032)
		(layers "F.Cu" "B.Cu")
		(net "GND")
	)
	(via
		(at 205.180946 -317.166752)
		(size 0.4572)
		(drill 0.2032)
		(layers "F.Cu" "B.Cu")
		(net "GND")
	)
	(via
		(at 422.945814 -273.587972)
		(size 0.4572)
		(drill 0.2032)
		(layers "F.Cu" "B.Cu")
		(net "GND")
	)
	(via
		(at 408.157426 -238.966756)
		(size 0.4572)
		(drill 0.2032)
		(layers "F.Cu" "B.Cu")
		(net "GND")
	)
	(via
		(at 16.598646 -108.28274)
		(size 0.508)
		(drill 0.254)
		(layers "F.Cu" "B.Cu")
		(net "GND")
	)
	(via
		(at 455.011282 -198.166736)
		(size 0.4572)
		(drill 0.2032)
		(layers "F.Cu" "B.Cu")
		(net "GND")
	)
	(via
		(at 129.496566 -222.761556)
		(size 0.4572)
		(drill 0.2032)
		(layers "F.Cu" "B.Cu")
		(net "GND")
	)
	(via
		(at 90.604848 -257.98907)
		(size 0.4572)
		(drill 0.2032)
		(layers "F.Cu" "B.Cu")
		(net "GND")
	)
	(via
		(at 171.562014 -204.116686)
		(size 0.4572)
		(drill 0.2032)
		(layers "F.Cu" "B.Cu")
		(net "GND")
	)
	(via
		(at 155.551378 -195.44919)
		(size 0.508)
		(drill 0.254)
		(layers "F.Cu" "B.Cu")
		(net "GND")
	)
	(via
		(at 159.82188 -120.106948)
		(size 0.508)
		(drill 0.254)
		(layers "F.Cu" "B.Cu")
		(net "GND")
	)
	(via
		(at 201.06386 -105.9307)
		(size 0.508)
		(drill 0.254)
		(layers "F.Cu" "B.Cu")
		(net "GND")
	)
	(via
		(at 66.152014 -245.76659)
		(size 0.4572)
		(drill 0.2032)
		(layers "F.Cu" "B.Cu")
		(net "GND")
	)
	(via
		(at 399.990056 -5.585714)
		(size 0.508)
		(drill 0.254)
		(layers "F.Cu" "B.Cu")
		(net "GND")
	)
	(via
		(at 58.608214 -286.56661)
		(size 0.4572)
		(drill 0.2032)
		(layers "F.Cu" "B.Cu")
		(net "GND")
	)
	(via
		(at 330.952856 -31.656782)
		(size 0.508)
		(drill 0.254)
		(layers "F.Cu" "B.Cu")
		(net "GND")
	)
	(via
		(at 129.22885 -358.111806)
		(size 0.508)
		(drill 0.254)
		(layers "F.Cu" "B.Cu")
		(net "GND")
	)
	(via
		(at 81.477866 -400.224244)
		(size 0.4572)
		(drill 0.254)
		(layers "F.Cu" "B.Cu")
		(net "GND")
	)
	(via
		(at 405.648414 -195.616576)
		(size 0.4572)
		(drill 0.2032)
		(layers "F.Cu" "B.Cu")
		(net "GND")
	)
	(via
		(at 180.339746 -238.966756)
		(size 0.4572)
		(drill 0.2032)
		(layers "F.Cu" "B.Cu")
		(net "GND")
	)
	(via
		(at 49.896522 -437.438038)
		(size 0.508)
		(drill 0.254)
		(layers "F.Cu" "B.Cu")
		(net "GND")
	)
	(via
		(at 141.038834 -400.858228)
		(size 0.4064)
		(drill 0.2032)
		(layers "F.Cu" "B.Cu")
		(net "GND")
	)
	(via
		(at 193.591688 -31.470092)
		(size 0.508)
		(drill 0.254)
		(layers "F.Cu" "B.Cu")
		(net "GND")
	)
	(via
		(at 458.455014 -290.816792)
		(size 0.4572)
		(drill 0.2032)
		(layers "F.Cu" "B.Cu")
		(net "GND")
	)
	(via
		(at 186.649614 -207.51673)
		(size 0.4572)
		(drill 0.2032)
		(layers "F.Cu" "B.Cu")
		(net "GND")
	)
	(via
		(at 435.823614 -304.416714)
		(size 0.4572)
		(drill 0.2032)
		(layers "F.Cu" "B.Cu")
		(net "GND")
	)
	(via
		(at 309.992014 -201.56678)
		(size 0.4572)
		(drill 0.2032)
		(layers "F.Cu" "B.Cu")
		(net "GND")
	)
	(via
		(at 433.860448 -19.125438)
		(size 0.508)
		(drill 0.254)
		(layers "F.Cu" "B.Cu")
		(net "GND")
	)
	(via
		(at 131.956048 -257.98907)
		(size 0.4572)
		(drill 0.2032)
		(layers "F.Cu" "B.Cu")
		(net "GND")
	)
	(via
		(at 122.447812 -238.225584)
		(size 0.4572)
		(drill 0.2032)
		(layers "F.Cu" "B.Cu")
		(net "GND")
	)
	(via
		(at 209.281014 -289.966654)
		(size 0.4572)
		(drill 0.2032)
		(layers "F.Cu" "B.Cu")
		(net "GND")
	)
	(via
		(at 356.980744 -60.548012)
		(size 0.508)
		(drill 0.254)
		(layers "F.Cu" "B.Cu")
		(net "GND")
	)
	(via
		(at 51.221894 -352.397822)
		(size 0.49022)
		(drill 0.254)
		(layers "F.Cu" "B.Cu")
		(net "GND")
	)
	(via
		(at 9.245346 -258.516628)
		(size 0.4572)
		(drill 0.2032)
		(layers "F.Cu" "B.Cu")
		(net "GND")
	)
	(via
		(at 167.461946 -195.616576)
		(size 0.4572)
		(drill 0.2032)
		(layers "F.Cu" "B.Cu")
		(net "GND")
	)
	(via
		(at 110.340394 -272.639282)
		(size 0.4572)
		(drill 0.2032)
		(layers "F.Cu" "B.Cu")
		(net "GND")
	)
	(via
		(at 424.836082 -267.866622)
		(size 0.4572)
		(drill 0.2032)
		(layers "F.Cu" "B.Cu")
		(net "GND")
	)
	(via
		(at 210.514946 -311.216802)
		(size 0.4572)
		(drill 0.2032)
		(layers "F.Cu" "B.Cu")
		(net "GND")
	)
	(via
		(at 287.360614 -260.21665)
		(size 0.4572)
		(drill 0.2032)
		(layers "F.Cu" "B.Cu")
		(net "GND")
	)
	(via
		(at 9.245346 -231.316784)
		(size 0.4572)
		(drill 0.2032)
		(layers "F.Cu" "B.Cu")
		(net "GND")
	)
	(via
		(at 426.285152 -323.429376)
		(size 0.4572)
		(drill 0.2032)
		(layers "F.Cu" "B.Cu")
		(net "GND")
	)
	(via
		(at 429.851312 -5.585714)
		(size 0.508)
		(drill 0.254)
		(layers "F.Cu" "B.Cu")
		(net "GND")
	)
	(via
		(at 175.259746 -292.516814)
		(size 0.4572)
		(drill 0.2032)
		(layers "F.Cu" "B.Cu")
		(net "GND")
	)
	(via
		(at 108.578396 -356.943406)
		(size 0.508)
		(drill 0.254)
		(layers "F.Cu" "B.Cu")
		(net "GND")
	)
	(via
		(at 165.252146 -278.066754)
		(size 0.4572)
		(drill 0.2032)
		(layers "F.Cu" "B.Cu")
		(net "GND")
	)
	(via
		(at 96.243394 -257.98907)
		(size 0.4572)
		(drill 0.2032)
		(layers "F.Cu" "B.Cu")
		(net "GND")
	)
	(via
		(at 348.77248 -238.225584)
		(size 0.4572)
		(drill 0.2032)
		(layers "F.Cu" "B.Cu")
		(net "GND")
	)
	(via
		(at 447.467482 -264.466578)
		(size 0.4572)
		(drill 0.2032)
		(layers "F.Cu" "B.Cu")
		(net "GND")
	)
	(via
		(at 361.569762 -275.08073)
		(size 0.4572)
		(drill 0.2032)
		(layers "F.Cu" "B.Cu")
		(net "GND")
	)
	(via
		(at 364.859062 -277.522432)
		(size 0.4572)
		(drill 0.2032)
		(layers "F.Cu" "B.Cu")
		(net "GND")
	)
	(via
		(at 453.121014 -273.816572)
		(size 0.4572)
		(drill 0.2032)
		(layers "F.Cu" "B.Cu")
		(net "GND")
	)
	(via
		(at 384.32994 -62.842648)
		(size 0.508)
		(drill 0.254)
		(layers "F.Cu" "B.Cu")
		(net "GND")
	)
	(via
		(at 56.398414 -230.466646)
		(size 0.4572)
		(drill 0.2032)
		(layers "F.Cu" "B.Cu")
		(net "GND")
	)
	(via
		(at 321.250056 -426.54728)
		(size 0.4572)
		(drill 0.2032)
		(layers "F.Cu" "B.Cu")
		(net "GND")
	)
	(via
		(at 270.063214 -273.816572)
		(size 0.4572)
		(drill 0.2032)
		(layers "F.Cu" "B.Cu")
		(net "GND")
	)
	(via
		(at 424.836082 -250.866656)
		(size 0.4572)
		(drill 0.2032)
		(layers "F.Cu" "B.Cu")
		(net "GND")
	)
	(via
		(at 82.462878 -410.030168)
		(size 0.4064)
		(drill 0.2032)
		(layers "F.Cu" "B.Cu")
		(net "GND")
	)
	(via
		(at 56.398414 -258.516628)
		(size 0.4572)
		(drill 0.2032)
		(layers "F.Cu" "B.Cu")
		(net "GND")
	)
	(via
		(at 33.767014 -224.516696)
		(size 0.4572)
		(drill 0.2032)
		(layers "F.Cu" "B.Cu")
		(net "GND")
	)
	(via
		(at 186.649614 -202.416664)
		(size 0.4572)
		(drill 0.2032)
		(layers "F.Cu" "B.Cu")
		(net "GND")
	)
	(via
		(at 33.86709 -17.61236)
		(size 0.508)
		(drill 0.254)
		(layers "F.Cu" "B.Cu")
		(net "GND")
	)
	(via
		(at 350.762316 -282.405836)
		(size 0.4572)
		(drill 0.2032)
		(layers "F.Cu" "B.Cu")
		(net "GND")
	)
	(via
		(at 97.543366 -229.272846)
		(size 0.4572)
		(drill 0.2032)
		(layers "F.Cu" "B.Cu")
		(net "GND")
	)
	(via
		(at 207.071214 -202.416664)
		(size 0.4572)
		(drill 0.2032)
		(layers "F.Cu" "B.Cu")
		(net "GND")
	)
	(via
		(at 424.836082 -278.916638)
		(size 0.4572)
		(drill 0.2032)
		(layers "F.Cu" "B.Cu")
		(net "GND")
	)
	(via
		(at 176.896014 -219.41663)
		(size 0.4572)
		(drill 0.2032)
		(layers "F.Cu" "B.Cu")
		(net "GND")
	)
	(via
		(at 262.519414 -236.416596)
		(size 0.4572)
		(drill 0.2032)
		(layers "F.Cu" "B.Cu")
		(net "GND")
	)
	(via
		(at 291.460682 -219.41663)
		(size 0.4572)
		(drill 0.2032)
		(layers "F.Cu" "B.Cu")
		(net "GND")
	)
	(via
		(at 427.045882 -211.766658)
		(size 0.4572)
		(drill 0.2032)
		(layers "F.Cu" "B.Cu")
		(net "GND")
	)
	(via
		(at 121.09196 -78.555088)
		(size 0.508)
		(drill 0.254)
		(layers "F.Cu" "B.Cu")
		(net "GND")
	)
	(via
		(at 121.447814 -332.56601)
		(size 0.49022)
		(drill 0.254)
		(layers "F.Cu" "B.Cu")
		(net "GND")
	)
	(via
		(at 133.365494 -270.19758)
		(size 0.4572)
		(drill 0.2032)
		(layers "F.Cu" "B.Cu")
		(net "GND")
	)
	(via
		(at 126.677166 -227.64496)
		(size 0.4572)
		(drill 0.2032)
		(layers "F.Cu" "B.Cu")
		(net "GND")
	)
	(via
		(at 89.664794 -271.011396)
		(size 0.4572)
		(drill 0.2032)
		(layers "F.Cu" "B.Cu")
		(net "GND")
	)
	(via
		(at 279.816814 -248.31675)
		(size 0.4572)
		(drill 0.2032)
		(layers "F.Cu" "B.Cu")
		(net "GND")
	)
	(via
		(at 329.273408 -407.00452)
		(size 0.4064)
		(drill 0.2032)
		(layers "F.Cu" "B.Cu")
		(net "GND")
	)
	(via
		(at 302.448214 -203.266802)
		(size 0.4572)
		(drill 0.2032)
		(layers "F.Cu" "B.Cu")
		(net "GND")
	)
	(via
		(at 35.976814 -266.1666)
		(size 0.4572)
		(drill 0.2032)
		(layers "F.Cu" "B.Cu")
		(net "GND")
	)
	(via
		(at 348.465648 -330.42352)
		(size 0.508)
		(drill 0.254)
		(layers "F.Cu" "B.Cu")
		(net "GND")
	)
	(via
		(at 356.400862 -279.150318)
		(size 0.4572)
		(drill 0.2032)
		(layers "F.Cu" "B.Cu")
		(net "GND")
	)
	(via
		(at 432.379882 -224.516696)
		(size 0.4572)
		(drill 0.2032)
		(layers "F.Cu" "B.Cu")
		(net "GND")
	)
	(via
		(at 320.3575 -403.249892)
		(size 0.4572)
		(drill 0.254)
		(layers "F.Cu" "B.Cu")
		(net "GND")
	)
	(via
		(at 218.7829 -15.664688)
		(size 0.508)
		(drill 0.254)
		(layers "F.Cu" "B.Cu")
		(net "GND")
	)
	(via
		(at 416.575494 -163.062158)
		(size 0.49022)
		(drill 0.254)
		(layers "F.Cu" "B.Cu")
		(net "GND")
	)
	(via
		(at 22.123146 -300.166786)
		(size 0.4572)
		(drill 0.2032)
		(layers "F.Cu" "B.Cu")
		(net "GND")
	)
	(via
		(at 143.34998 -435.0512)
		(size 0.4572)
		(drill 0.2032)
		(layers "F.Cu" "B.Cu")
		(net "GND")
	)
	(via
		(at 424.836082 -245.76659)
		(size 0.4572)
		(drill 0.2032)
		(layers "F.Cu" "B.Cu")
		(net "GND")
	)
	(via
		(at 165.252146 -287.213548)
		(size 0.4572)
		(drill 0.2032)
		(layers "F.Cu" "B.Cu")
		(net "GND")
	)
	(via
		(at 104.121966 -230.900478)
		(size 0.4572)
		(drill 0.2032)
		(layers "F.Cu" "B.Cu")
		(net "GND")
	)
	(via
		(at 453.121014 -270.416782)
		(size 0.4572)
		(drill 0.2032)
		(layers "F.Cu" "B.Cu")
		(net "GND")
	)
	(via
		(at 59.842146 -225.36658)
		(size 0.4572)
		(drill 0.2032)
		(layers "F.Cu" "B.Cu")
		(net "GND")
	)
	(via
		(at 166.871142 -431.476658)
		(size 0.508)
		(drill 0.254)
		(layers "F.Cu" "B.Cu")
		(net "GND")
	)
	(via
		(at 63.942214 -247.466612)
		(size 0.4572)
		(drill 0.2032)
		(layers "F.Cu" "B.Cu")
		(net "GND")
	)
	(via
		(at 333.26578 -232.528364)
		(size 0.4572)
		(drill 0.2032)
		(layers "F.Cu" "B.Cu")
		(net "GND")
	)
	(via
		(at 56.83885 -163.101274)
		(size 0.49022)
		(drill 0.254)
		(layers "F.Cu" "B.Cu")
		(net "GND")
	)
	(via
		(at 135.245348 -275.080984)
		(size 0.4572)
		(drill 0.2032)
		(layers "F.Cu" "B.Cu")
		(net "GND")
	)
	(via
		(at 419.796468 -219.41663)
		(size 0.4572)
		(drill 0.2032)
		(layers "F.Cu" "B.Cu")
		(net "GND")
	)
	(via
		(at 90.667586 -403.249892)
		(size 0.4572)
		(drill 0.254)
		(layers "F.Cu" "B.Cu")
		(net "GND")
	)
	(via
		(at 414.070292 -160.744154)
		(size 0.49022)
		(drill 0.254)
		(layers "F.Cu" "B.Cu")
		(net "GND")
	)
	(via
		(at 457.221082 -280.61666)
		(size 0.4572)
		(drill 0.2032)
		(layers "F.Cu" "B.Cu")
		(net "GND")
	)
	(via
		(at 333.510128 -54.558946)
		(size 0.4572)
		(drill 0.2032)
		(layers "F.Cu" "B.Cu")
		(net "GND")
	)
	(via
		(at 294.175688 -58.459878)
		(size 0.508)
		(drill 0.254)
		(layers "F.Cu" "B.Cu")
		(net "GND")
	)
	(via
		(at 166.269924 -363.525562)
		(size 0.4572)
		(drill 0.254)
		(layers "F.Cu" "B.Cu")
		(net "GND")
	)
	(via
		(at 281.707082 -303.566576)
		(size 0.4572)
		(drill 0.2032)
		(layers "F.Cu" "B.Cu")
		(net "GND")
	)
	(via
		(at 370.497862 -279.150318)
		(size 0.4572)
		(drill 0.2032)
		(layers "F.Cu" "B.Cu")
		(net "GND")
	)
	(via
		(at 427.510194 -4.317746)
		(size 0.508)
		(drill 0.254)
		(layers "F.Cu" "B.Cu")
		(net "GND")
	)
	(via
		(at 432.379882 -299.316648)
		(size 0.4572)
		(drill 0.2032)
		(layers "F.Cu" "B.Cu")
		(net "GND")
	)
	(via
		(at 178.960272 -359.186226)
		(size 0.508)
		(drill 0.254)
		(layers "F.Cu" "B.Cu")
		(net "GND")
	)
	(via
		(at 457.221082 -262.76681)
		(size 0.4572)
		(drill 0.2032)
		(layers "F.Cu" "B.Cu")
		(net "GND")
	)
	(via
		(at 359.58018 -229.272846)
		(size 0.4572)
		(drill 0.2032)
		(layers "F.Cu" "B.Cu")
		(net "GND")
	)
	(via
		(at 139.989814 -341.77097)
		(size 0.49022)
		(drill 0.254)
		(layers "F.Cu" "B.Cu")
		(net "GND")
	)
	(via
		(at 370.027962 -283.219906)
		(size 0.4572)
		(drill 0.2032)
		(layers "F.Cu" "B.Cu")
		(net "GND")
	)
	(via
		(at 314.23102 -400.224244)
		(size 0.4572)
		(drill 0.254)
		(layers "F.Cu" "B.Cu")
		(net "GND")
	)
	(via
		(at 447.467482 -297.616626)
		(size 0.4572)
		(drill 0.2032)
		(layers "F.Cu" "B.Cu")
		(net "GND")
	)
	(via
		(at 165.082728 -285.65856)
		(size 0.4572)
		(drill 0.2032)
		(layers "F.Cu" "B.Cu")
		(net "GND")
	)
	(via
		(at 184.580276 -350.261682)
		(size 0.508)
		(drill 0.254)
		(layers "F.Cu" "B.Cu")
		(net "GND")
	)
	(via
		(at 347.473016 -273.453098)
		(size 0.4572)
		(drill 0.2032)
		(layers "F.Cu" "B.Cu")
		(net "GND")
	)
	(via
		(at 86.824566 -335.976214)
		(size 0.49022)
		(drill 0.254)
		(layers "F.Cu" "B.Cu")
		(net "GND")
	)
	(via
		(at 340.290658 -45.630846)
		(size 0.4572)
		(drill 0.2032)
		(layers "F.Cu" "B.Cu")
		(net "GND")
	)
	(via
		(at 138.107166 -250.155964)
		(size 0.4572)
		(drill 0.2032)
		(layers "F.Cu" "B.Cu")
		(net "GND")
	)
	(via
		(at 14.899132 -191.55283)
		(size 0.508)
		(drill 0.254)
		(layers "F.Cu" "B.Cu")
		(net "GND")
	)
	(via
		(at 228.50475 -120.359424)
		(size 0.508)
		(drill 0.254)
		(layers "F.Cu" "B.Cu")
		(net "GND")
	)
	(via
		(at 55.259224 -158.64205)
		(size 0.49022)
		(drill 0.254)
		(layers "F.Cu" "B.Cu")
		(net "GND")
	)
	(via
		(at 276.373082 -232.166668)
		(size 0.4572)
		(drill 0.2032)
		(layers "F.Cu" "B.Cu")
		(net "GND")
	)
	(via
		(at 352.062034 -221.133924)
		(size 0.4572)
		(drill 0.2032)
		(layers "F.Cu" "B.Cu")
		(net "GND")
	)
	(via
		(at 332.32598 -237.411768)
		(size 0.4572)
		(drill 0.2032)
		(layers "F.Cu" "B.Cu")
		(net "GND")
	)
	(via
		(at 261.285482 -294.216582)
		(size 0.4572)
		(drill 0.2032)
		(layers "F.Cu" "B.Cu")
		(net "GND")
	)
	(via
		(at 432.379882 -244.066568)
		(size 0.4572)
		(drill 0.2032)
		(layers "F.Cu" "B.Cu")
		(net "GND")
	)
	(via
		(at 453.894952 -392.971274)
		(size 0.6604)
		(drill 0.3302)
		(layers "F.Cu" "B.Cu")
		(net "GND")
	)
	(via
		(at 376.893582 -409.396184)
		(size 0.4572)
		(drill 0.254)
		(layers "F.Cu" "B.Cu")
		(net "GND")
	)
	(via
		(at 443.367414 -199.01662)
		(size 0.4572)
		(drill 0.2032)
		(layers "F.Cu" "B.Cu")
		(net "GND")
	)
	(via
		(at 293.757096 -359.513124)
		(size 0.508)
		(drill 0.254)
		(layers "F.Cu" "B.Cu")
		(net "GND")
	)
	(via
		(at 122.562366 -407.638504)
		(size 0.4572)
		(drill 0.254)
		(layers "F.Cu" "B.Cu")
		(net "GND")
	)
	(via
		(at 176.896014 -308.666642)
		(size 0.4572)
		(drill 0.2032)
		(layers "F.Cu" "B.Cu")
		(net "GND")
	)
	(via
		(at 261.285482 -280.61666)
		(size 0.4572)
		(drill 0.2032)
		(layers "F.Cu" "B.Cu")
		(net "GND")
	)
	(via
		(at 419.502082 -250.866656)
		(size 0.4572)
		(drill 0.2032)
		(layers "F.Cu" "B.Cu")
		(net "GND")
	)
	(via
		(at 413.192214 -281.466798)
		(size 0.4572)
		(drill 0.2032)
		(layers "F.Cu" "B.Cu")
		(net "GND")
	)
	(via
		(at 444.243206 -96.572324)
		(size 0.508)
		(drill 0.254)
		(layers "F.Cu" "B.Cu")
		(net "GND")
	)
	(via
		(at 101.882194 -284.033722)
		(size 0.4572)
		(drill 0.2032)
		(layers "F.Cu" "B.Cu")
		(net "GND")
	)
	(via
		(at 368.916204 -243.84635)
		(size 0.4572)
		(drill 0.2032)
		(layers "F.Cu" "B.Cu")
		(net "GND")
	)
	(via
		(at 347.363034 -243.922804)
		(size 0.4572)
		(drill 0.2032)
		(layers "F.Cu" "B.Cu")
		(net "GND")
	)
	(via
		(at 371.437662 -277.522432)
		(size 0.4572)
		(drill 0.2032)
		(layers "F.Cu" "B.Cu")
		(net "GND")
	)
	(via
		(at 209.281014 -316.316614)
		(size 0.4572)
		(drill 0.2032)
		(layers "F.Cu" "B.Cu")
		(net "GND")
	)
	(via
		(at 382.135634 -216.25052)
		(size 0.4572)
		(drill 0.2032)
		(layers "F.Cu" "B.Cu")
		(net "GND")
	)
	(via
		(at 187.883546 -197.316598)
		(size 0.4572)
		(drill 0.2032)
		(layers "F.Cu" "B.Cu")
		(net "GND")
	)
	(via
		(at 277.607014 -203.266802)
		(size 0.4572)
		(drill 0.2032)
		(layers "F.Cu" "B.Cu")
		(net "GND")
	)
	(via
		(at 129.496566 -240.667286)
		(size 0.4572)
		(drill 0.2032)
		(layers "F.Cu" "B.Cu")
		(net "GND")
	)
	(via
		(at 354.051362 -276.708616)
		(size 0.4572)
		(drill 0.2032)
		(layers "F.Cu" "B.Cu")
		(net "GND")
	)
	(via
		(at 201.737214 -289.966654)
		(size 0.4572)
		(drill 0.2032)
		(layers "F.Cu" "B.Cu")
		(net "GND")
	)
	(via
		(at 33.35909 -16.978376)
		(size 0.508)
		(drill 0.254)
		(layers "F.Cu" "B.Cu")
		(net "GND")
	)
	(via
		(at 345.026234 -47.949612)
		(size 0.4572)
		(drill 0.2032)
		(layers "F.Cu" "B.Cu")
		(net "GND")
	)
	(via
		(at 182.549546 -216.016586)
		(size 0.4572)
		(drill 0.2032)
		(layers "F.Cu" "B.Cu")
		(net "GND")
	)
	(via
		(at 179.105814 -294.216582)
		(size 0.4572)
		(drill 0.2032)
		(layers "F.Cu" "B.Cu")
		(net "GND")
	)
	(via
		(at 138.534394 -282.405836)
		(size 0.4572)
		(drill 0.2032)
		(layers "F.Cu" "B.Cu")
		(net "GND")
	)
	(via
		(at 425.817284 -360.148378)
		(size 0.49022)
		(drill 0.254)
		(layers "F.Cu" "B.Cu")
		(net "GND")
	)
	(via
		(at 314.092082 -247.466612)
		(size 0.4572)
		(drill 0.2032)
		(layers "F.Cu" "B.Cu")
		(net "GND")
	)
	(via
		(at 161.611564 -219.41663)
		(size 0.4572)
		(drill 0.2032)
		(layers "F.Cu" "B.Cu")
		(net "GND")
	)
	(via
		(at 116.918994 -264.50036)
		(size 0.4572)
		(drill 0.2032)
		(layers "F.Cu" "B.Cu")
		(net "GND")
	)
	(via
		(at 424.836082 -297.616626)
		(size 0.4572)
		(drill 0.2032)
		(layers "F.Cu" "B.Cu")
		(net "GND")
	)
	(via
		(at 169.137584 -235.566712)
		(size 0.4572)
		(drill 0.2032)
		(layers "F.Cu" "B.Cu")
		(net "GND")
	)
	(via
		(at 409.330398 -407.638504)
		(size 0.4572)
		(drill 0.254)
		(layers "F.Cu" "B.Cu")
		(net "GND")
	)
	(via
		(at 87.14613 -409.396184)
		(size 0.4572)
		(drill 0.254)
		(layers "F.Cu" "B.Cu")
		(net "GND")
	)
	(via
		(at 76.697586 -409.396184)
		(size 0.4572)
		(drill 0.254)
		(layers "F.Cu" "B.Cu")
		(net "GND")
	)
	(via
		(at 428.279814 -233.016806)
		(size 0.4572)
		(drill 0.2032)
		(layers "F.Cu" "B.Cu")
		(net "GND")
	)
	(via
		(at 180.339746 -225.36658)
		(size 0.4572)
		(drill 0.2032)
		(layers "F.Cu" "B.Cu")
		(net "GND")
	)
	(via
		(at 317.250064 -432.451256)
		(size 0.4572)
		(drill 0.2032)
		(layers "F.Cu" "B.Cu")
		(net "GND")
	)
	(via
		(at 130.906012 -230.086662)
		(size 0.4572)
		(drill 0.2032)
		(layers "F.Cu" "B.Cu")
		(net "GND")
	)
	(via
		(at 344.86342 -404.51786)
		(size 0.4572)
		(drill 0.254)
		(layers "F.Cu" "B.Cu")
		(net "GND")
	)
	(via
		(at 84.250022 -427.851316)
		(size 0.4572)
		(drill 0.2032)
		(layers "F.Cu" "B.Cu")
		(net "GND")
	)
	(via
		(at 120.97385 -259.749544)
		(size 0.4572)
		(drill 0.2032)
		(layers "F.Cu" "B.Cu")
		(net "GND")
	)
	(via
		(at 169.352214 -202.416664)
		(size 0.4572)
		(drill 0.2032)
		(layers "F.Cu" "B.Cu")
		(net "GND")
	)
	(via
		(at 453.121014 -276.366732)
		(size 0.4572)
		(drill 0.2032)
		(layers "F.Cu" "B.Cu")
		(net "GND")
	)
	(via
		(at 190.80988 -134.711948)
		(size 0.508)
		(drill 0.254)
		(layers "F.Cu" "B.Cu")
		(net "GND")
	)
	(via
		(at 372.847362 -286.475424)
		(size 0.4572)
		(drill 0.2032)
		(layers "F.Cu" "B.Cu")
		(net "GND")
	)
	(via
		(at 94.71533 -441.225432)
		(size 0.508)
		(drill 0.254)
		(layers "F.Cu" "B.Cu")
		(net "GND")
	)
	(via
		(at 50.581306 -107.412028)
		(size 0.508)
		(drill 0.254)
		(layers "F.Cu" "B.Cu")
		(net "GND")
	)
	(via
		(at 340.250272 -44.711112)
		(size 0.4572)
		(drill 0.2032)
		(layers "F.Cu" "B.Cu")
		(net "GND")
	)
	(via
		(at 410.35732 -165.123368)
		(size 0.508)
		(drill 0.254)
		(layers "F.Cu" "B.Cu")
		(net "GND")
	)
	(via
		(at 337.025234 -219.506038)
		(size 0.4572)
		(drill 0.2032)
		(layers "F.Cu" "B.Cu")
		(net "GND")
	)
	(via
		(at 237.96752 -387.37794)
		(size 0.508)
		(drill 0.254)
		(layers "F.Cu" "B.Cu")
		(net "GND")
	)
	(via
		(at 316.596776 -65.048892)
		(size 0.508)
		(drill 0.254)
		(layers "F.Cu" "B.Cu")
		(net "GND")
	)
	(via
		(at 458.455014 -258.516628)
		(size 0.4572)
		(drill 0.2032)
		(layers "F.Cu" "B.Cu")
		(net "GND")
	)
	(via
		(at 401.349972 -439.651394)
		(size 0.4572)
		(drill 0.2032)
		(layers "F.Cu" "B.Cu")
		(net "GND")
	)
	(via
		(at 186.649614 -294.216582)
		(size 0.4572)
		(drill 0.2032)
		(layers "F.Cu" "B.Cu")
		(net "GND")
	)
	(via
		(at 62.267846 -287.416748)
		(size 0.4572)
		(drill 0.2032)
		(layers "F.Cu" "B.Cu")
		(net "GND")
	)
	(via
		(at 350.822006 -236.425994)
		(size 0.4572)
		(drill 0.2032)
		(layers "F.Cu" "B.Cu")
		(net "GND")
	)
	(via
		(at 100.362766 -227.64496)
		(size 0.4572)
		(drill 0.2032)
		(layers "F.Cu" "B.Cu")
		(net "GND")
	)
	(via
		(at 174.942754 -350.754188)
		(size 0.508)
		(drill 0.254)
		(layers "F.Cu" "B.Cu")
		(net "GND")
	)
	(via
		(at 165.252146 -295.06672)
		(size 0.4572)
		(drill 0.2032)
		(layers "F.Cu" "B.Cu")
		(net "GND")
	)
	(via
		(at 341.364062 -287.28924)
		(size 0.4572)
		(drill 0.2032)
		(layers "F.Cu" "B.Cu")
		(net "GND")
	)
	(via
		(at 60.698634 -323.685662)
		(size 0.4572)
		(drill 0.2032)
		(layers "F.Cu" "B.Cu")
		(net "GND")
	)
	(via
		(at 452.628 -31.99257)
		(size 0.508)
		(drill 0.254)
		(layers "F.Cu" "B.Cu")
		(net "GND")
	)
	(via
		(at 259.075682 -316.316614)
		(size 0.4572)
		(drill 0.2032)
		(layers "F.Cu" "B.Cu")
		(net "GND")
	)
	(via
		(at 26.223214 -261.066788)
		(size 0.4572)
		(drill 0.2032)
		(layers "F.Cu" "B.Cu")
		(net "GND")
	)
	(via
		(at 287.360614 -298.466764)
		(size 0.4572)
		(drill 0.2032)
		(layers "F.Cu" "B.Cu")
		(net "GND")
	)
	(via
		(at 381.305562 -265.314176)
		(size 0.4572)
		(drill 0.2032)
		(layers "F.Cu" "B.Cu")
		(net "GND")
	)
	(via
		(at 197.637146 -304.416714)
		(size 0.4572)
		(drill 0.2032)
		(layers "F.Cu" "B.Cu")
		(net "GND")
	)
	(via
		(at 422.945814 -214.316564)
		(size 0.4572)
		(drill 0.2032)
		(layers "F.Cu" "B.Cu")
		(net "GND")
	)
	(via
		(at 95.245174 -33.383982)
		(size 0.508)
		(drill 0.254)
		(layers "F.Cu" "B.Cu")
		(net "GND")
	)
	(via
		(at 131.956048 -262.872474)
		(size 0.4572)
		(drill 0.2032)
		(layers "F.Cu" "B.Cu")
		(net "GND")
	)
	(via
		(at 58.233056 -144.300702)
		(size 0.508)
		(drill 0.254)
		(layers "F.Cu" "B.Cu")
		(net "GND")
	)
	(via
		(at 74.536808 -20.950682)
		(size 0.508)
		(drill 0.254)
		(layers "F.Cu" "B.Cu")
		(net "GND")
	)
	(via
		(at 268.829282 -213.46668)
		(size 0.4572)
		(drill 0.2032)
		(layers "F.Cu" "B.Cu")
		(net "GND")
	)
	(via
		(at 39.420546 -206.666592)
		(size 0.4572)
		(drill 0.2032)
		(layers "F.Cu" "B.Cu")
		(net "GND")
	)
	(via
		(at 44.754546 -309.51678)
		(size 0.4572)
		(drill 0.2032)
		(layers "F.Cu" "B.Cu")
		(net "GND")
	)
	(via
		(at 311.882282 -244.066568)
		(size 0.4572)
		(drill 0.2032)
		(layers "F.Cu" "B.Cu")
		(net "GND")
	)
	(via
		(at 39.420546 -263.616694)
		(size 0.4572)
		(drill 0.2032)
		(layers "F.Cu" "B.Cu")
		(net "GND")
	)
	(via
		(at 367.098834 -219.506038)
		(size 0.4572)
		(drill 0.2032)
		(layers "F.Cu" "B.Cu")
		(net "GND")
	)
	(via
		(at 51.064414 -288.266632)
		(size 0.4572)
		(drill 0.2032)
		(layers "F.Cu" "B.Cu")
		(net "GND")
	)
	(via
		(at 335.6737 -403.249892)
		(size 0.4572)
		(drill 0.254)
		(layers "F.Cu" "B.Cu")
		(net "GND")
	)
	(via
		(at 254.975614 -313.766708)
		(size 0.4572)
		(drill 0.2032)
		(layers "F.Cu" "B.Cu")
		(net "GND")
	)
	(via
		(at 102.5652 -15.154148)
		(size 0.508)
		(drill 0.254)
		(layers "F.Cu" "B.Cu")
		(net "GND")
	)
	(via
		(at 87.205312 -227.64496)
		(size 0.4572)
		(drill 0.2032)
		(layers "F.Cu" "B.Cu")
		(net "GND")
	)
	(via
		(at 462.039716 -318.512444)
		(size 0.4572)
		(drill 0.2032)
		(layers "F.Cu" "B.Cu")
		(net "GND")
	)
	(via
		(at 409.490672 -235.566712)
		(size 0.4572)
		(drill 0.2032)
		(layers "F.Cu" "B.Cu")
		(net "GND")
	)
	(via
		(at 384.48488 -239.853216)
		(size 0.4572)
		(drill 0.2032)
		(layers "F.Cu" "B.Cu")
		(net "GND")
	)
	(via
		(at 296.794682 -222.816674)
		(size 0.4572)
		(drill 0.2032)
		(layers "F.Cu" "B.Cu")
		(net "GND")
	)
	(via
		(at 300.238414 -240.666778)
		(size 0.4572)
		(drill 0.2032)
		(layers "F.Cu" "B.Cu")
		(net "GND")
	)
	(via
		(at 100.472748 -275.08073)
		(size 0.4572)
		(drill 0.2032)
		(layers "F.Cu" "B.Cu")
		(net "GND")
	)
	(via
		(at 335.270856 -339.114638)
		(size 0.49022)
		(drill 0.254)
		(layers "F.Cu" "B.Cu")
		(net "GND")
	)
	(via
		(at 291.460682 -295.916604)
		(size 0.4572)
		(drill 0.2032)
		(layers "F.Cu" "B.Cu")
		(net "GND")
	)
	(via
		(at 35.976814 -222.816674)
		(size 0.4572)
		(drill 0.2032)
		(layers "F.Cu" "B.Cu")
		(net "GND")
	)
	(via
		(at 378.956062 -262.872474)
		(size 0.4572)
		(drill 0.2032)
		(layers "F.Cu" "B.Cu")
		(net "GND")
	)
	(via
		(at 75.351386 -400.224244)
		(size 0.4572)
		(drill 0.254)
		(layers "F.Cu" "B.Cu")
		(net "GND")
	)
	(via
		(at 342.773762 -253.919736)
		(size 0.4572)
		(drill 0.2032)
		(layers "F.Cu" "B.Cu")
		(net "GND")
	)
	(via
		(at 443.367414 -233.016806)
		(size 0.4572)
		(drill 0.2032)
		(layers "F.Cu" "B.Cu")
		(net "GND")
	)
	(via
		(at 117.859048 -280.778204)
		(size 0.4572)
		(drill 0.2032)
		(layers "F.Cu" "B.Cu")
		(net "GND")
	)
	(via
		(at 180.339746 -311.216802)
		(size 0.4572)
		(drill 0.2032)
		(layers "F.Cu" "B.Cu")
		(net "GND")
	)
	(via
		(at 358.280716 -288.993326)
		(size 0.4572)
		(drill 0.2032)
		(layers "F.Cu" "B.Cu")
		(net "GND")
	)
	(via
		(at 462.555082 -271.266666)
		(size 0.4572)
		(drill 0.2032)
		(layers "F.Cu" "B.Cu")
		(net "GND")
	)
	(via
		(at 262.519414 -270.416782)
		(size 0.4572)
		(drill 0.2032)
		(layers "F.Cu" "B.Cu")
		(net "GND")
	)
	(via
		(at 210.514946 -244.916706)
		(size 0.4572)
		(drill 0.2032)
		(layers "F.Cu" "B.Cu")
		(net "GND")
	)
	(via
		(at 394.349986 -427.851316)
		(size 0.4572)
		(drill 0.2032)
		(layers "F.Cu" "B.Cu")
		(net "GND")
	)
	(via
		(at 306.548282 -277.216616)
		(size 0.4572)
		(drill 0.2032)
		(layers "F.Cu" "B.Cu")
		(net "GND")
	)
	(via
		(at 151.848566 -403.249892)
		(size 0.4572)
		(drill 0.254)
		(layers "F.Cu" "B.Cu")
		(net "GND")
	)
	(via
		(at 175.005746 -197.316598)
		(size 0.4572)
		(drill 0.2032)
		(layers "F.Cu" "B.Cu")
		(net "GND")
	)
	(via
		(at 363.684566 -358.74198)
		(size 0.508)
		(drill 0.254)
		(layers "F.Cu" "B.Cu")
		(net "GND")
	)
	(via
		(at 162.384486 -407.638504)
		(size 0.4572)
		(drill 0.254)
		(layers "F.Cu" "B.Cu")
		(net "GND")
	)
	(via
		(at 460.664814 -246.616728)
		(size 0.4572)
		(drill 0.2032)
		(layers "F.Cu" "B.Cu")
		(net "GND")
	)
	(via
		(at 202.971146 -285.716726)
		(size 0.4572)
		(drill 0.2032)
		(layers "F.Cu" "B.Cu")
		(net "GND")
	)
	(via
		(at 419.241478 -360.074972)
		(size 0.508)
		(drill 0.254)
		(layers "F.Cu" "B.Cu")
		(net "GND")
	)
	(via
		(at 63.250064 -435.0512)
		(size 0.4572)
		(drill 0.2032)
		(layers "F.Cu" "B.Cu")
		(net "GND")
	)
	(via
		(at 449.677282 -282.316682)
		(size 0.4572)
		(drill 0.2032)
		(layers "F.Cu" "B.Cu")
		(net "GND")
	)
	(via
		(at 396.926562 -6.07949)
		(size 0.508)
		(drill 0.254)
		(layers "F.Cu" "B.Cu")
		(net "GND")
	)
	(via
		(at 439.923682 -194.766692)
		(size 0.4572)
		(drill 0.2032)
		(layers "F.Cu" "B.Cu")
		(net "GND")
	)
	(via
		(at 95.303594 -272.639282)
		(size 0.4572)
		(drill 0.2032)
		(layers "F.Cu" "B.Cu")
		(net "GND")
	)
	(via
		(at 159.918146 -240.666778)
		(size 0.4572)
		(drill 0.2032)
		(layers "F.Cu" "B.Cu")
		(net "GND")
	)
	(via
		(at 161.808414 -291.666676)
		(size 0.4572)
		(drill 0.2032)
		(layers "F.Cu" "B.Cu")
		(net "GND")
	)
	(via
		(at 16.789146 -265.316716)
		(size 0.4572)
		(drill 0.2032)
		(layers "F.Cu" "B.Cu")
		(net "GND")
	)
	(via
		(at 354.61321 -358.848406)
		(size 0.508)
		(drill 0.254)
		(layers "F.Cu" "B.Cu")
		(net "GND")
	)
	(via
		(at 449.677282 -269.566644)
		(size 0.4572)
		(drill 0.2032)
		(layers "F.Cu" "B.Cu")
		(net "GND")
	)
	(via
		(at 349.71228 -243.108988)
		(size 0.4572)
		(drill 0.2032)
		(layers "F.Cu" "B.Cu")
		(net "GND")
	)
	(via
		(at 109.38637 -14.903958)
		(size 0.508)
		(drill 0.254)
		(layers "F.Cu" "B.Cu")
		(net "GND")
	)
	(via
		(at 375.634758 -410.664152)
		(size 0.4572)
		(drill 0.254)
		(layers "F.Cu" "B.Cu")
		(net "GND")
	)
	(via
		(at 335.725262 -256.361438)
		(size 0.4572)
		(drill 0.2032)
		(layers "F.Cu" "B.Cu")
		(net "GND")
	)
	(via
		(at 16.789146 -197.316598)
		(size 0.4572)
		(drill 0.2032)
		(layers "F.Cu" "B.Cu")
		(net "GND")
	)
	(via
		(at 216.824814 -250.866656)
		(size 0.4572)
		(drill 0.2032)
		(layers "F.Cu" "B.Cu")
		(net "GND")
	)
	(via
		(at 169.352214 -215.166702)
		(size 0.4572)
		(drill 0.2032)
		(layers "F.Cu" "B.Cu")
		(net "GND")
	)
	(via
		(at 335.900776 -339.114638)
		(size 0.49022)
		(drill 0.254)
		(layers "F.Cu" "B.Cu")
		(net "GND")
	)
	(via
		(at 66.152014 -239.81664)
		(size 0.4572)
		(drill 0.2032)
		(layers "F.Cu" "B.Cu")
		(net "GND")
	)
	(via
		(at 423.68216 -144.689068)
		(size 0.508)
		(drill 0.254)
		(layers "F.Cu" "B.Cu")
		(net "GND")
	)
	(via
		(at 350.182434 -222.761556)
		(size 0.4572)
		(drill 0.2032)
		(layers "F.Cu" "B.Cu")
		(net "GND")
	)
	(via
		(at 171.562014 -196.466714)
		(size 0.4572)
		(drill 0.2032)
		(layers "F.Cu" "B.Cu")
		(net "GND")
	)
	(via
		(at 413.50438 -158.435548)
		(size 0.508)
		(drill 0.254)
		(layers "F.Cu" "B.Cu")
		(net "GND")
	)
	(via
		(at 453.121014 -233.016806)
		(size 0.4572)
		(drill 0.2032)
		(layers "F.Cu" "B.Cu")
		(net "GND")
	)
	(via
		(at 112.484662 -139.069826)
		(size 0.508)
		(drill 0.254)
		(layers "F.Cu" "B.Cu")
		(net "GND")
	)
	(via
		(at 378.956316 -277.522432)
		(size 0.4572)
		(drill 0.2032)
		(layers "F.Cu" "B.Cu")
		(net "GND")
	)
	(via
		(at 89.554812 -230.086662)
		(size 0.4572)
		(drill 0.2032)
		(layers "F.Cu" "B.Cu")
		(net "GND")
	)
	(via
		(at 427.045882 -262.76681)
		(size 0.4572)
		(drill 0.2032)
		(layers "F.Cu" "B.Cu")
		(net "GND")
	)
	(via
		(at 187.883546 -217.716608)
		(size 0.4572)
		(drill 0.2032)
		(layers "F.Cu" "B.Cu")
		(net "GND")
	)
	(via
		(at 463.150204 -383.010664)
		(size 0.508)
		(drill 0.254)
		(layers "F.Cu" "B.Cu")
		(net "GND")
	)
	(via
		(at 380.415038 -400.224244)
		(size 0.4572)
		(drill 0.254)
		(layers "F.Cu" "B.Cu")
		(net "GND")
	)
	(via
		(at 187.883546 -267.016738)
		(size 0.4572)
		(drill 0.2032)
		(layers "F.Cu" "B.Cu")
		(net "GND")
	)
	(via
		(at 148.785326 -400.224244)
		(size 0.4572)
		(drill 0.254)
		(layers "F.Cu" "B.Cu")
		(net "GND")
	)
	(via
		(at 62.051946 -240.666778)
		(size 0.4572)
		(drill 0.2032)
		(layers "F.Cu" "B.Cu")
		(net "GND")
	)
	(via
		(at 266.619482 -271.266666)
		(size 0.4572)
		(drill 0.2032)
		(layers "F.Cu" "B.Cu")
		(net "GND")
	)
	(via
		(at 115.722908 -358.732836)
		(size 0.508)
		(drill 0.254)
		(layers "F.Cu" "B.Cu")
		(net "GND")
	)
	(via
		(at 76.336398 -410.030168)
		(size 0.4064)
		(drill 0.2032)
		(layers "F.Cu" "B.Cu")
		(net "GND")
	)
	(via
		(at 98.953066 -217.064336)
		(size 0.4572)
		(drill 0.2032)
		(layers "F.Cu" "B.Cu")
		(net "GND")
	)
	(via
		(at 62.737238 -403.883876)
		(size 0.4064)
		(drill 0.2032)
		(layers "F.Cu" "B.Cu")
		(net "GND")
	)
	(via
		(at 330.847446 -341.067136)
		(size 0.49022)
		(drill 0.254)
		(layers "F.Cu" "B.Cu")
		(net "GND")
	)
	(via
		(at 372.377462 -271.011396)
		(size 0.4572)
		(drill 0.2032)
		(layers "F.Cu" "B.Cu")
		(net "GND")
	)
	(via
		(at 304.083974 -397.151098)
		(size 0.508)
		(drill 0.254)
		(layers "F.Cu" "B.Cu")
		(net "GND")
	)
	(via
		(at 411.349952 -425.547282)
		(size 0.4572)
		(drill 0.2032)
		(layers "F.Cu" "B.Cu")
		(net "GND")
	)
	(via
		(at 180.339746 -250.016772)
		(size 0.4572)
		(drill 0.2032)
		(layers "F.Cu" "B.Cu")
		(net "GND")
	)
	(via
		(at 131.376166 -216.25052)
		(size 0.4572)
		(drill 0.2032)
		(layers "F.Cu" "B.Cu")
		(net "GND")
	)
	(via
		(at 104.121966 -232.528364)
		(size 0.4572)
		(drill 0.2032)
		(layers "F.Cu" "B.Cu")
		(net "GND")
	)
	(via
		(at 39.420546 -273.816572)
		(size 0.4572)
		(drill 0.2032)
		(layers "F.Cu" "B.Cu")
		(net "GND")
	)
	(via
		(at 79.20228 -152.085548)
		(size 0.508)
		(drill 0.254)
		(layers "F.Cu" "B.Cu")
		(net "GND")
	)
	(via
		(at 162.842702 -404.51786)
		(size 0.4572)
		(drill 0.254)
		(layers "F.Cu" "B.Cu")
		(net "GND")
	)
	(via
		(at 59.842146 -267.016738)
		(size 0.4572)
		(drill 0.2032)
		(layers "F.Cu" "B.Cu")
		(net "GND")
	)
	(via
		(at 450.911214 -307.816758)
		(size 0.4572)
		(drill 0.2032)
		(layers "F.Cu" "B.Cu")
		(net "GND")
	)
	(via
		(at 262.519414 -240.666778)
		(size 0.4572)
		(drill 0.2032)
		(layers "F.Cu" "B.Cu")
		(net "GND")
	)
	(via
		(at 87.315294 -270.19758)
		(size 0.4572)
		(drill 0.2032)
		(layers "F.Cu" "B.Cu")
		(net "GND")
	)
	(via
		(at 88.250014 -430.299622)
		(size 0.4572)
		(drill 0.2032)
		(layers "F.Cu" "B.Cu")
		(net "GND")
	)
	(via
		(at 177.561748 -350.754188)
		(size 0.508)
		(drill 0.254)
		(layers "F.Cu" "B.Cu")
		(net "GND")
	)
	(via
		(at 292.694614 -304.416714)
		(size 0.4572)
		(drill 0.2032)
		(layers "F.Cu" "B.Cu")
		(net "GND")
	)
	(via
		(at 171.821348 -312.91657)
		(size 0.4572)
		(drill 0.2032)
		(layers "F.Cu" "B.Cu")
		(net "GND")
	)
	(via
		(at 384.015234 -229.272846)
		(size 0.4572)
		(drill 0.2032)
		(layers "F.Cu" "B.Cu")
		(net "GND")
	)
	(via
		(at 415.967418 -149.972776)
		(size 0.508)
		(drill 0.254)
		(layers "F.Cu" "B.Cu")
		(net "GND")
	)
	(via
		(at 288.754566 -361.625388)
		(size 0.49022)
		(drill 0.254)
		(layers "F.Cu" "B.Cu")
		(net "GND")
	)
	(via
		(at 256.667 -68.544948)
		(size 0.508)
		(drill 0.254)
		(layers "F.Cu" "B.Cu")
		(net "GND")
	)
	(via
		(at 257.972052 -97.273872)
		(size 0.508)
		(drill 0.254)
		(layers "F.Cu" "B.Cu")
		(net "GND")
	)
	(via
		(at 325.128128 -407.00452)
		(size 0.4064)
		(drill 0.2032)
		(layers "F.Cu" "B.Cu")
		(net "GND")
	)
	(via
		(at 416.836606 -6.07949)
		(size 0.508)
		(drill 0.254)
		(layers "F.Cu" "B.Cu")
		(net "GND")
	)
	(via
		(at 292.694614 -197.316598)
		(size 0.4572)
		(drill 0.2032)
		(layers "F.Cu" "B.Cu")
		(net "GND")
	)
	(via
		(at 285.150814 -229.616762)
		(size 0.4572)
		(drill 0.2032)
		(layers "F.Cu" "B.Cu")
		(net "GND")
	)
	(via
		(at 207.071214 -258.516628)
		(size 0.4572)
		(drill 0.2032)
		(layers "F.Cu" "B.Cu")
		(net "GND")
	)
	(via
		(at 169.352214 -226.216718)
		(size 0.4572)
		(drill 0.2032)
		(layers "F.Cu" "B.Cu")
		(net "GND")
	)
	(via
		(at 449.677282 -194.766692)
		(size 0.4572)
		(drill 0.2032)
		(layers "F.Cu" "B.Cu")
		(net "GND")
	)
	(via
		(at 147.349972 -435.0512)
		(size 0.4572)
		(drill 0.2032)
		(layers "F.Cu" "B.Cu")
		(net "GND")
	)
	(via
		(at 52.787296 -173.11624)
		(size 0.49022)
		(drill 0.254)
		(layers "F.Cu" "B.Cu")
		(net "GND")
	)
	(via
		(at 351.122234 -226.017328)
		(size 0.4572)
		(drill 0.2032)
		(layers "F.Cu" "B.Cu")
		(net "GND")
	)
	(via
		(at 341.724234 -247.178322)
		(size 0.4572)
		(drill 0.2032)
		(layers "F.Cu" "B.Cu")
		(net "GND")
	)
	(via
		(at 29.666946 -300.166786)
		(size 0.4572)
		(drill 0.2032)
		(layers "F.Cu" "B.Cu")
		(net "GND")
	)
	(via
		(at 436.368952 -386.321554)
		(size 0.508)
		(drill 0.254)
		(layers "F.Cu" "B.Cu")
		(net "GND")
	)
	(via
		(at 427.27372 -137.93851)
		(size 0.508)
		(drill 0.254)
		(layers "F.Cu" "B.Cu")
		(net "GND")
	)
	(via
		(at 176.896014 -207.51673)
		(size 0.4572)
		(drill 0.2032)
		(layers "F.Cu" "B.Cu")
		(net "GND")
	)
	(via
		(at 41.310814 -312.91657)
		(size 0.4572)
		(drill 0.2032)
		(layers "F.Cu" "B.Cu")
		(net "GND")
	)
	(via
		(at 82.104738 -335.50225)
		(size 0.6604)
		(drill 0.3302)
		(layers "F.Cu" "B.Cu")
		(net "GND")
	)
	(via
		(at 120.97639 -245.015004)
		(size 0.4572)
		(drill 0.2032)
		(layers "F.Cu" "B.Cu")
		(net "GND")
	)
	(via
		(at 187.883546 -315.46673)
		(size 0.4572)
		(drill 0.2032)
		(layers "F.Cu" "B.Cu")
		(net "GND")
	)
	(via
		(at 268.829282 -278.916638)
		(size 0.4572)
		(drill 0.2032)
		(layers "F.Cu" "B.Cu")
		(net "GND")
	)
	(via
		(at 117.823996 -254.01524)
		(size 0.4572)
		(drill 0.2032)
		(layers "F.Cu" "B.Cu")
		(net "GND")
	)
	(via
		(at 374.257316 -264.50036)
		(size 0.4572)
		(drill 0.2032)
		(layers "F.Cu" "B.Cu")
		(net "GND")
	)
	(via
		(at 37.688266 -16.978376)
		(size 0.508)
		(drill 0.254)
		(layers "F.Cu" "B.Cu")
		(net "GND")
	)
	(via
		(at 102.42804 -111.595408)
		(size 0.508)
		(drill 0.254)
		(layers "F.Cu" "B.Cu")
		(net "GND")
	)
	(via
		(at 28.433014 -291.666676)
		(size 0.4572)
		(drill 0.2032)
		(layers "F.Cu" "B.Cu")
		(net "GND")
	)
	(via
		(at 261.285482 -210.066636)
		(size 0.4572)
		(drill 0.2032)
		(layers "F.Cu" "B.Cu")
		(net "GND")
	)
	(via
		(at 447.467482 -316.316614)
		(size 0.4572)
		(drill 0.2032)
		(layers "F.Cu" "B.Cu")
		(net "GND")
	)
	(via
		(at 366.269016 -270.19758)
		(size 0.4572)
		(drill 0.2032)
		(layers "F.Cu" "B.Cu")
		(net "GND")
	)
	(via
		(at 279.816814 -260.21665)
		(size 0.4572)
		(drill 0.2032)
		(layers "F.Cu" "B.Cu")
		(net "GND")
	)
	(via
		(at 379.319536 -106.492802)
		(size 0.508)
		(drill 0.254)
		(layers "F.Cu" "B.Cu")
		(net "GND")
	)
	(via
		(at 99.40544 -125.910848)
		(size 0.508)
		(drill 0.254)
		(layers "F.Cu" "B.Cu")
		(net "GND")
	)
	(via
		(at 413.192214 -206.666592)
		(size 0.4572)
		(drill 0.2032)
		(layers "F.Cu" "B.Cu")
		(net "GND")
	)
	(via
		(at 334.205834 -224.389442)
		(size 0.4572)
		(drill 0.2032)
		(layers "F.Cu" "B.Cu")
		(net "GND")
	)
	(via
		(at 340.784434 -222.761556)
		(size 0.4572)
		(drill 0.2032)
		(layers "F.Cu" "B.Cu")
		(net "GND")
	)
	(via
		(at 122.659394 -400.858228)
		(size 0.4064)
		(drill 0.2032)
		(layers "F.Cu" "B.Cu")
		(net "GND")
	)
	(via
		(at 420.736014 -287.416748)
		(size 0.4572)
		(drill 0.2032)
		(layers "F.Cu" "B.Cu")
		(net "GND")
	)
	(via
		(at 304.338482 -267.866622)
		(size 0.4572)
		(drill 0.2032)
		(layers "F.Cu" "B.Cu")
		(net "GND")
	)
	(via
		(at 195.20408 -350.510348)
		(size 0.508)
		(drill 0.254)
		(layers "F.Cu" "B.Cu")
		(net "GND")
	)
	(via
		(at 107.991148 -268.569694)
		(size 0.4572)
		(drill 0.2032)
		(layers "F.Cu" "B.Cu")
		(net "GND")
	)
	(via
		(at 309.45074 -409.396184)
		(size 0.4572)
		(drill 0.254)
		(layers "F.Cu" "B.Cu")
		(net "GND")
	)
	(via
		(at 133.469126 -401.492212)
		(size 0.4572)
		(drill 0.254)
		(layers "F.Cu" "B.Cu")
		(net "GND")
	)
	(via
		(at 314.092082 -226.216718)
		(size 0.4572)
		(drill 0.2032)
		(layers "F.Cu" "B.Cu")
		(net "GND")
	)
	(via
		(at 244.819424 -100.127308)
		(size 0.508)
		(drill 0.254)
		(layers "F.Cu" "B.Cu")
		(net "GND")
	)
	(via
		(at 97.653348 -253.919736)
		(size 0.4572)
		(drill 0.2032)
		(layers "F.Cu" "B.Cu")
		(net "GND")
	)
	(via
		(at 434.589682 -310.366664)
		(size 0.4572)
		(drill 0.2032)
		(layers "F.Cu" "B.Cu")
		(net "GND")
	)
	(via
		(at 120.127014 -331.776832)
		(size 0.49022)
		(drill 0.254)
		(layers "F.Cu" "B.Cu")
		(net "GND")
	)
	(via
		(at 283.916882 -222.816674)
		(size 0.4572)
		(drill 0.2032)
		(layers "F.Cu" "B.Cu")
		(net "GND")
	)
	(via
		(at 180.955696 -111.775494)
		(size 0.4572)
		(drill 0.254)
		(layers "F.Cu" "B.Cu")
		(net "GND")
	)
	(via
		(at 86.250018 -439.651394)
		(size 0.4572)
		(drill 0.2032)
		(layers "F.Cu" "B.Cu")
		(net "GND")
	)
	(via
		(at 115.039394 -264.50036)
		(size 0.4572)
		(drill 0.2032)
		(layers "F.Cu" "B.Cu")
		(net "GND")
	)
	(via
		(at 438.033414 -214.316564)
		(size 0.4572)
		(drill 0.2032)
		(layers "F.Cu" "B.Cu")
		(net "GND")
	)
	(via
		(at 28.433014 -301.01667)
		(size 0.4572)
		(drill 0.2032)
		(layers "F.Cu" "B.Cu")
		(net "GND")
	)
	(via
		(at 8.520684 -323.434456)
		(size 0.4572)
		(drill 0.2032)
		(layers "F.Cu" "B.Cu")
		(net "GND")
	)
	(via
		(at 446.389506 -71.021194)
		(size 0.508)
		(drill 0.254)
		(layers "F.Cu" "B.Cu")
		(net "GND")
	)
	(via
		(at 384.824478 -410.664152)
		(size 0.4572)
		(drill 0.254)
		(layers "F.Cu" "B.Cu")
		(net "GND")
	)
	(via
		(at 346.306648 -403.883876)
		(size 0.4064)
		(drill 0.2032)
		(layers "F.Cu" "B.Cu")
		(net "GND")
	)
	(via
		(at 46.964346 -290.816792)
		(size 0.4572)
		(drill 0.2032)
		(layers "F.Cu" "B.Cu")
		(net "GND")
	)
	(via
		(at 378.97181 -400.858228)
		(size 0.4064)
		(drill 0.2032)
		(layers "F.Cu" "B.Cu")
		(net "GND")
	)
	(via
		(at 174.5107 -20.119848)
		(size 0.508)
		(drill 0.254)
		(layers "F.Cu" "B.Cu")
		(net "GND")
	)
	(via
		(at 314.092082 -239.81664)
		(size 0.4572)
		(drill 0.2032)
		(layers "F.Cu" "B.Cu")
		(net "GND")
	)
	(via
		(at 201.737214 -282.316682)
		(size 0.4572)
		(drill 0.2032)
		(layers "F.Cu" "B.Cu")
		(net "GND")
	)
	(via
		(at 416.556952 -12.37488)
		(size 0.508)
		(drill 0.254)
		(layers "F.Cu" "B.Cu")
		(net "GND")
	)
	(via
		(at 123.967494 -279.964134)
		(size 0.4572)
		(drill 0.2032)
		(layers "F.Cu" "B.Cu")
		(net "GND")
	)
	(via
		(at 368.618516 -279.150318)
		(size 0.4572)
		(drill 0.2032)
		(layers "F.Cu" "B.Cu")
		(net "GND")
	)
	(via
		(at 61.29401 -400.224244)
		(size 0.4572)
		(drill 0.254)
		(layers "F.Cu" "B.Cu")
		(net "GND")
	)
	(via
		(at 90.964766 -248.806208)
		(size 0.4572)
		(drill 0.2032)
		(layers "F.Cu" "B.Cu")
		(net "GND")
	)
	(via
		(at 387.29158 -49.731168)
		(size 0.508)
		(drill 0.254)
		(layers "F.Cu" "B.Cu")
		(net "GND")
	)
	(via
		(at 44.754546 -233.016806)
		(size 0.4572)
		(drill 0.2032)
		(layers "F.Cu" "B.Cu")
		(net "GND")
	)
	(via
		(at 187.883546 -295.06672)
		(size 0.4572)
		(drill 0.2032)
		(layers "F.Cu" "B.Cu")
		(net "GND")
	)
	(via
		(at 98.953066 -223.575626)
		(size 0.4572)
		(drill 0.2032)
		(layers "F.Cu" "B.Cu")
		(net "GND")
	)
	(via
		(at 109.870494 -278.336502)
		(size 0.4572)
		(drill 0.2032)
		(layers "F.Cu" "B.Cu")
		(net "GND")
	)
	(via
		(at 9.245346 -273.816572)
		(size 0.4572)
		(drill 0.2032)
		(layers "F.Cu" "B.Cu")
		(net "GND")
	)
	(via
		(at 13.345414 -303.566576)
		(size 0.4572)
		(drill 0.2032)
		(layers "F.Cu" "B.Cu")
		(net "GND")
	)
	(via
		(at 37.210746 -206.666592)
		(size 0.4572)
		(drill 0.2032)
		(layers "F.Cu" "B.Cu")
		(net "GND")
	)
	(via
		(at 181.407308 -45.17771)
		(size 0.508)
		(drill 0.254)
		(layers "F.Cu" "B.Cu")
		(net "GND")
	)
	(via
		(at 257.185414 -229.616762)
		(size 0.4572)
		(drill 0.2032)
		(layers "F.Cu" "B.Cu")
		(net "GND")
	)
	(via
		(at 266.619482 -215.166702)
		(size 0.4572)
		(drill 0.2032)
		(layers "F.Cu" "B.Cu")
		(net "GND")
	)
	(via
		(at 185.75782 -15.420848)
		(size 0.508)
		(drill 0.254)
		(layers "F.Cu" "B.Cu")
		(net "GND")
	)
	(via
		(at 303.657 -51.939444)
		(size 0.508)
		(drill 0.254)
		(layers "F.Cu" "B.Cu")
		(net "GND")
	)
	(via
		(at 155.956 -139.9032)
		(size 0.508)
		(drill 0.254)
		(layers "F.Cu" "B.Cu")
		(net "GND")
	)
	(via
		(at 35.807396 -100.80879)
		(size 0.508)
		(drill 0.254)
		(layers "F.Cu" "B.Cu")
		(net "GND")
	)
	(via
		(at 339.766402 -330.454254)
		(size 0.508)
		(drill 0.254)
		(layers "F.Cu" "B.Cu")
		(net "GND")
	)
	(via
		(at 384.124962 -276.708616)
		(size 0.4572)
		(drill 0.2032)
		(layers "F.Cu" "B.Cu")
		(net "GND")
	)
	(via
		(at 449.677282 -228.766624)
		(size 0.4572)
		(drill 0.2032)
		(layers "F.Cu" "B.Cu")
		(net "GND")
	)
	(via
		(at 56.398414 -198.166736)
		(size 0.4572)
		(drill 0.2032)
		(layers "F.Cu" "B.Cu")
		(net "GND")
	)
	(via
		(at 56.51373 -410.664152)
		(size 0.4572)
		(drill 0.254)
		(layers "F.Cu" "B.Cu")
		(net "GND")
	)
	(via
		(at 44.754546 -240.666778)
		(size 0.4572)
		(drill 0.2032)
		(layers "F.Cu" "B.Cu")
		(net "GND")
	)
	(via
		(at 374.288558 -400.224244)
		(size 0.4572)
		(drill 0.254)
		(layers "F.Cu" "B.Cu")
		(net "GND")
	)
	(via
		(at 62.051946 -289.11677)
		(size 0.4572)
		(drill 0.2032)
		(layers "F.Cu" "B.Cu")
		(net "GND")
	)
	(via
		(at 342.664034 -216.25052)
		(size 0.4572)
		(drill 0.2032)
		(layers "F.Cu" "B.Cu")
		(net "GND")
	)
	(via
		(at 340.17712 -32.04845)
		(size 0.508)
		(drill 0.254)
		(layers "F.Cu" "B.Cu")
		(net "GND")
	)
	(via
		(at 20.924266 -16.978376)
		(size 0.508)
		(drill 0.254)
		(layers "F.Cu" "B.Cu")
		(net "GND")
	)
	(via
		(at 259.075682 -305.266598)
		(size 0.4572)
		(drill 0.2032)
		(layers "F.Cu" "B.Cu")
		(net "GND")
	)
	(via
		(at 39.420546 -292.516814)
		(size 0.4572)
		(drill 0.2032)
		(layers "F.Cu" "B.Cu")
		(net "GND")
	)
	(via
		(at 201.737214 -271.266666)
		(size 0.4572)
		(drill 0.2032)
		(layers "F.Cu" "B.Cu")
		(net "GND")
	)
	(via
		(at 406.54097 -400.858228)
		(size 0.4064)
		(drill 0.2032)
		(layers "F.Cu" "B.Cu")
		(net "GND")
	)
	(via
		(at 423.677588 -18.235422)
		(size 0.508)
		(drill 0.254)
		(layers "F.Cu" "B.Cu")
		(net "GND")
	)
	(via
		(at 98.013266 -238.225584)
		(size 0.4572)
		(drill 0.2032)
		(layers "F.Cu" "B.Cu")
		(net "GND")
	)
	(via
		(at 176.896014 -210.066636)
		(size 0.4572)
		(drill 0.2032)
		(layers "F.Cu" "B.Cu")
		(net "GND")
	)
	(via
		(at 216.824814 -198.166736)
		(size 0.4572)
		(drill 0.2032)
		(layers "F.Cu" "B.Cu")
		(net "GND")
	)
	(via
		(at 126.787148 -270.19758)
		(size 0.4572)
		(drill 0.2032)
		(layers "F.Cu" "B.Cu")
		(net "GND")
	)
	(via
		(at 20.889214 -310.366664)
		(size 0.4572)
		(drill 0.2032)
		(layers "F.Cu" "B.Cu")
		(net "GND")
	)
	(via
		(at 169.27195 -359.2068)
		(size 0.508)
		(drill 0.254)
		(layers "F.Cu" "B.Cu")
		(net "GND")
	)
	(via
		(at 448.78752 -58.887868)
		(size 0.508)
		(drill 0.254)
		(layers "F.Cu" "B.Cu")
		(net "GND")
	)
	(via
		(at 52.082446 -208.366614)
		(size 0.4572)
		(drill 0.2032)
		(layers "F.Cu" "B.Cu")
		(net "GND")
	)
	(via
		(at 331.666596 -277.410672)
		(size 0.4572)
		(drill 0.2032)
		(layers "F.Cu" "B.Cu")
		(net "GND")
	)
	(via
		(at 56.398414 -286.56661)
		(size 0.4572)
		(drill 0.2032)
		(layers "F.Cu" "B.Cu")
		(net "GND")
	)
	(via
		(at 386.474716 -280.778204)
		(size 0.4572)
		(drill 0.2032)
		(layers "F.Cu" "B.Cu")
		(net "GND")
	)
	(via
		(at 138.34999 -433.899564)
		(size 0.4572)
		(drill 0.2032)
		(layers "F.Cu" "B.Cu")
		(net "GND")
	)
	(via
		(at 254.975614 -201.56678)
		(size 0.4572)
		(drill 0.2032)
		(layers "F.Cu" "B.Cu")
		(net "GND")
	)
	(via
		(at 182.549546 -278.066754)
		(size 0.4572)
		(drill 0.2032)
		(layers "F.Cu" "B.Cu")
		(net "GND")
	)
	(via
		(at 9.245346 -250.016772)
		(size 0.4572)
		(drill 0.2032)
		(layers "F.Cu" "B.Cu")
		(net "GND")
	)
	(via
		(at 445.760602 -78.861412)
		(size 0.508)
		(drill 0.254)
		(layers "F.Cu" "B.Cu")
		(net "GND")
	)
	(via
		(at 284.126686 -12.544552)
		(size 0.508)
		(drill 0.254)
		(layers "F.Cu" "B.Cu")
		(net "GND")
	)
	(via
		(at 428.279814 -270.416782)
		(size 0.4572)
		(drill 0.2032)
		(layers "F.Cu" "B.Cu")
		(net "GND")
	)
	(via
		(at 245.311168 -89.143586)
		(size 0.508)
		(drill 0.254)
		(layers "F.Cu" "B.Cu")
		(net "GND")
	)
	(via
		(at 109.77753 -329.722226)
		(size 0.508)
		(drill 0.254)
		(layers "F.Cu" "B.Cu")
		(net "GND")
	)
	(via
		(at 420.736014 -258.516628)
		(size 0.4572)
		(drill 0.2032)
		(layers "F.Cu" "B.Cu")
		(net "GND")
	)
	(via
		(at 445.577214 -296.766742)
		(size 0.4572)
		(drill 0.2032)
		(layers "F.Cu" "B.Cu")
		(net "GND")
	)
	(via
		(at 128.556766 -242.294918)
		(size 0.4572)
		(drill 0.2032)
		(layers "F.Cu" "B.Cu")
		(net "GND")
	)
	(via
		(at 54.792118 -16.978376)
		(size 0.508)
		(drill 0.254)
		(layers "F.Cu" "B.Cu")
		(net "GND")
	)
	(via
		(at 214.615014 -308.666642)
		(size 0.4572)
		(drill 0.2032)
		(layers "F.Cu" "B.Cu")
		(net "GND")
	)
	(via
		(at 199.527414 -239.81664)
		(size 0.4572)
		(drill 0.2032)
		(layers "F.Cu" "B.Cu")
		(net "GND")
	)
	(via
		(at 161.125662 -409.396184)
		(size 0.4572)
		(drill 0.254)
		(layers "F.Cu" "B.Cu")
		(net "GND")
	)
	(via
		(at 344.363294 -48.919892)
		(size 0.4572)
		(drill 0.2032)
		(layers "F.Cu" "B.Cu")
		(net "GND")
	)
	(via
		(at 128.556766 -247.178322)
		(size 0.4572)
		(drill 0.2032)
		(layers "F.Cu" "B.Cu")
		(net "GND")
	)
	(via
		(at 159.918146 -212.616796)
		(size 0.4572)
		(drill 0.2032)
		(layers "F.Cu" "B.Cu")
		(net "GND")
	)
	(via
		(at 26.223214 -222.816674)
		(size 0.4572)
		(drill 0.2032)
		(layers "F.Cu" "B.Cu")
		(net "GND")
	)
	(via
		(at 41.310814 -258.516628)
		(size 0.4572)
		(drill 0.2032)
		(layers "F.Cu" "B.Cu")
		(net "GND")
	)
	(via
		(at 130.076194 -287.28924)
		(size 0.4572)
		(drill 0.2032)
		(layers "F.Cu" "B.Cu")
		(net "GND")
	)
	(via
		(at 352.172016 -266.941808)
		(size 0.4572)
		(drill 0.2032)
		(layers "F.Cu" "B.Cu")
		(net "GND")
	)
	(via
		(at 441.5028 -49.240948)
		(size 0.508)
		(drill 0.254)
		(layers "F.Cu" "B.Cu")
		(net "GND")
	)
	(via
		(at 340.424516 -282.405836)
		(size 0.4572)
		(drill 0.2032)
		(layers "F.Cu" "B.Cu")
		(net "GND")
	)
	(via
		(at 324.753478 -68.447158)
		(size 0.508)
		(drill 0.254)
		(layers "F.Cu" "B.Cu")
		(net "GND")
	)
	(via
		(at 87.675466 -226.831144)
		(size 0.4572)
		(drill 0.2032)
		(layers "F.Cu" "B.Cu")
		(net "GND")
	)
	(via
		(at 205.180946 -208.366614)
		(size 0.4572)
		(drill 0.2032)
		(layers "F.Cu" "B.Cu")
		(net "GND")
	)
	(via
		(at 92.844366 -216.25052)
		(size 0.4572)
		(drill 0.2032)
		(layers "F.Cu" "B.Cu")
		(net "GND")
	)
	(via
		(at 93.16085 -32.426148)
		(size 0.508)
		(drill 0.254)
		(layers "F.Cu" "B.Cu")
		(net "GND")
	)
	(via
		(at 464.764882 -258.516628)
		(size 0.4572)
		(drill 0.2032)
		(layers "F.Cu" "B.Cu")
		(net "GND")
	)
	(via
		(at 442.133482 -314.616592)
		(size 0.4572)
		(drill 0.2032)
		(layers "F.Cu" "B.Cu")
		(net "GND")
	)
	(via
		(at 302.664114 -217.716608)
		(size 0.4572)
		(drill 0.2032)
		(layers "F.Cu" "B.Cu")
		(net "GND")
	)
	(via
		(at 353.396804 -254.014986)
		(size 0.4572)
		(drill 0.2032)
		(layers "F.Cu" "B.Cu")
		(net "GND")
	)
	(via
		(at 106.800396 -360.753406)
		(size 0.508)
		(drill 0.254)
		(layers "F.Cu" "B.Cu")
		(net "GND")
	)
	(via
		(at 175.005746 -309.51678)
		(size 0.4572)
		(drill 0.2032)
		(layers "F.Cu" "B.Cu")
		(net "GND")
	)
	(via
		(at 449.677282 -303.566576)
		(size 0.4572)
		(drill 0.2032)
		(layers "F.Cu" "B.Cu")
		(net "GND")
	)
	(via
		(at 390.349994 -426.69968)
		(size 0.4572)
		(drill 0.2032)
		(layers "F.Cu" "B.Cu")
		(net "GND")
	)
	(via
		(at 199.527414 -269.566644)
		(size 0.4572)
		(drill 0.2032)
		(layers "F.Cu" "B.Cu")
		(net "GND")
	)
	(via
		(at 176.238154 -350.093788)
		(size 0.508)
		(drill 0.254)
		(layers "F.Cu" "B.Cu")
		(net "GND")
	)
	(via
		(at 240.91773 -127.707136)
		(size 0.508)
		(drill 0.254)
		(layers "F.Cu" "B.Cu")
		(net "GND")
	)
	(via
		(at 428.279814 -276.366732)
		(size 0.4572)
		(drill 0.2032)
		(layers "F.Cu" "B.Cu")
		(net "GND")
	)
	(via
		(at 355.652578 -60.517278)
		(size 0.508)
		(drill 0.254)
		(layers "F.Cu" "B.Cu")
		(net "GND")
	)
	(via
		(at 356.30866 -331.71892)
		(size 0.508)
		(drill 0.254)
		(layers "F.Cu" "B.Cu")
		(net "GND")
	)
	(via
		(at 342.304116 -275.8948)
		(size 0.4572)
		(drill 0.2032)
		(layers "F.Cu" "B.Cu")
		(net "GND")
	)
	(via
		(at 97.543366 -219.506038)
		(size 0.4572)
		(drill 0.2032)
		(layers "F.Cu" "B.Cu")
		(net "GND")
	)
	(via
		(at 365.76381 -254.014986)
		(size 0.4572)
		(drill 0.2032)
		(layers "F.Cu" "B.Cu")
		(net "GND")
	)
	(via
		(at 41.435528 -125.297946)
		(size 0.508)
		(drill 0.254)
		(layers "F.Cu" "B.Cu")
		(net "GND")
	)
	(via
		(at 352.172016 -271.825212)
		(size 0.4572)
		(drill 0.2032)
		(layers "F.Cu" "B.Cu")
		(net "GND")
	)
	(via
		(at 194.825112 -23.23846)
		(size 0.508)
		(drill 0.254)
		(layers "F.Cu" "B.Cu")
		(net "GND")
	)
	(via
		(at 41.310814 -249.166634)
		(size 0.4572)
		(drill 0.2032)
		(layers "F.Cu" "B.Cu")
		(net "GND")
	)
	(via
		(at 131.486148 -283.219906)
		(size 0.4572)
		(drill 0.2032)
		(layers "F.Cu" "B.Cu")
		(net "GND")
	)
	(via
		(at 43.520614 -301.01667)
		(size 0.4572)
		(drill 0.2032)
		(layers "F.Cu" "B.Cu")
		(net "GND")
	)
	(via
		(at 302.448214 -287.416748)
		(size 0.4572)
		(drill 0.2032)
		(layers "F.Cu" "B.Cu")
		(net "GND")
	)
	(via
		(at 43.520614 -291.666676)
		(size 0.4572)
		(drill 0.2032)
		(layers "F.Cu" "B.Cu")
		(net "GND")
	)
	(via
		(at 398.43329 -400.858228)
		(size 0.4064)
		(drill 0.2032)
		(layers "F.Cu" "B.Cu")
		(net "GND")
	)
	(via
		(at 276.373082 -226.216718)
		(size 0.4572)
		(drill 0.2032)
		(layers "F.Cu" "B.Cu")
		(net "GND")
	)
	(via
		(at 251.333 -95.595948)
		(size 0.508)
		(drill 0.254)
		(layers "F.Cu" "B.Cu")
		(net "GND")
	)
	(via
		(at 62.051946 -225.36658)
		(size 0.4572)
		(drill 0.2032)
		(layers "F.Cu" "B.Cu")
		(net "GND")
	)
	(via
		(at 447.467482 -280.61666)
		(size 0.4572)
		(drill 0.2032)
		(layers "F.Cu" "B.Cu")
		(net "GND")
	)
	(via
		(at 311.255156 -406.370536)
		(size 0.4572)
		(drill 0.254)
		(layers "F.Cu" "B.Cu")
		(net "GND")
	)
	(via
		(at 383.07518 -217.878406)
		(size 0.4572)
		(drill 0.2032)
		(layers "F.Cu" "B.Cu")
		(net "GND")
	)
	(via
		(at 32.9184 -170.0276)
		(size 0.508)
		(drill 0.254)
		(layers "F.Cu" "B.Cu")
		(net "GND")
	)
	(via
		(at 382.715262 -285.661354)
		(size 0.4572)
		(drill 0.2032)
		(layers "F.Cu" "B.Cu")
		(net "GND")
	)
	(via
		(at 394.900658 -160.407858)
		(size 0.508)
		(drill 0.254)
		(layers "F.Cu" "B.Cu")
		(net "GND")
	)
	(via
		(at 134.195566 -230.900478)
		(size 0.4572)
		(drill 0.2032)
		(layers "F.Cu" "B.Cu")
		(net "GND")
	)
	(via
		(at 405.349964 -438.499758)
		(size 0.4572)
		(drill 0.2032)
		(layers "F.Cu" "B.Cu")
		(net "GND")
	)
	(via
		(at 419.502082 -233.86669)
		(size 0.4572)
		(drill 0.2032)
		(layers "F.Cu" "B.Cu")
		(net "GND")
	)
	(via
		(at 309.992014 -300.166786)
		(size 0.4572)
		(drill 0.2032)
		(layers "F.Cu" "B.Cu")
		(net "GND")
	)
	(via
		(at 98.013266 -233.34218)
		(size 0.4572)
		(drill 0.2032)
		(layers "F.Cu" "B.Cu")
		(net "GND")
	)
	(via
		(at 41.310814 -289.966654)
		(size 0.4572)
		(drill 0.2032)
		(layers "F.Cu" "B.Cu")
		(net "GND")
	)
	(via
		(at 19.181064 -110.875826)
		(size 0.508)
		(drill 0.254)
		(layers "F.Cu" "B.Cu")
		(net "GND")
	)
	(via
		(at 184.439814 -250.866656)
		(size 0.4572)
		(drill 0.2032)
		(layers "F.Cu" "B.Cu")
		(net "GND")
	)
	(via
		(at 380.725934 -247.992138)
		(size 0.4572)
		(drill 0.2032)
		(layers "F.Cu" "B.Cu")
		(net "GND")
	)
	(via
		(at 120.97639 -250.857004)
		(size 0.4572)
		(drill 0.2032)
		(layers "F.Cu" "B.Cu")
		(net "GND")
	)
	(via
		(at 459.95209 -41.652444)
		(size 0.508)
		(drill 0.254)
		(layers "F.Cu" "B.Cu")
		(net "GND")
	)
	(via
		(at 423.169588 -17.601438)
		(size 0.508)
		(drill 0.254)
		(layers "F.Cu" "B.Cu")
		(net "GND")
	)
	(via
		(at 30.56509 -18.502376)
		(size 0.508)
		(drill 0.254)
		(layers "F.Cu" "B.Cu")
		(net "GND")
	)
	(via
		(at 125.847094 -276.708616)
		(size 0.4572)
		(drill 0.2032)
		(layers "F.Cu" "B.Cu")
		(net "GND")
	)
	(via
		(at 388.293864 -77.954886)
		(size 0.508)
		(drill 0.254)
		(layers "F.Cu" "B.Cu")
		(net "GND")
	)
	(via
		(at 409.419044 -288.266632)
		(size 0.4572)
		(drill 0.2032)
		(layers "F.Cu" "B.Cu")
		(net "GND")
	)
	(via
		(at 268.829282 -299.316648)
		(size 0.4572)
		(drill 0.2032)
		(layers "F.Cu" "B.Cu")
		(net "GND")
	)
	(via
		(at 432.379882 -230.466646)
		(size 0.4572)
		(drill 0.2032)
		(layers "F.Cu" "B.Cu")
		(net "GND")
	)
	(via
		(at 422.55694 -100.260658)
		(size 0.508)
		(drill 0.254)
		(layers "F.Cu" "B.Cu")
		(net "GND")
	)
	(via
		(at 9.245346 -278.066754)
		(size 0.4572)
		(drill 0.2032)
		(layers "F.Cu" "B.Cu")
		(net "GND")
	)
	(via
		(at 16.789146 -233.016806)
		(size 0.4572)
		(drill 0.2032)
		(layers "F.Cu" "B.Cu")
		(net "GND")
	)
	(via
		(at 216.824814 -316.316614)
		(size 0.4572)
		(drill 0.2032)
		(layers "F.Cu" "B.Cu")
		(net "GND")
	)
	(via
		(at 23.718266 -18.502376)
		(size 0.508)
		(drill 0.254)
		(layers "F.Cu" "B.Cu")
		(net "GND")
	)
	(via
		(at 423.195242 -387.314948)
		(size 0.508)
		(drill 0.254)
		(layers "F.Cu" "B.Cu")
		(net "GND")
	)
	(via
		(at 205.180946 -281.466798)
		(size 0.4572)
		(drill 0.2032)
		(layers "F.Cu" "B.Cu")
		(net "GND")
	)
	(via
		(at 29.666946 -272.116804)
		(size 0.4572)
		(drill 0.2032)
		(layers "F.Cu" "B.Cu")
		(net "GND")
	)
	(via
		(at 100.942394 -264.50036)
		(size 0.4572)
		(drill 0.2032)
		(layers "F.Cu" "B.Cu")
		(net "GND")
	)
	(via
		(at 323.250052 -432.747166)
		(size 0.4572)
		(drill 0.2032)
		(layers "F.Cu" "B.Cu")
		(net "GND")
	)
	(via
		(at 44.754546 -279.766776)
		(size 0.4572)
		(drill 0.2032)
		(layers "F.Cu" "B.Cu")
		(net "GND")
	)
	(via
		(at 129.026666 -223.575626)
		(size 0.4572)
		(drill 0.2032)
		(layers "F.Cu" "B.Cu")
		(net "GND")
	)
	(via
		(at 13.345414 -264.466578)
		(size 0.4572)
		(drill 0.2032)
		(layers "F.Cu" "B.Cu")
		(net "GND")
	)
	(via
		(at 137.594594 -267.755878)
		(size 0.4572)
		(drill 0.2032)
		(layers "F.Cu" "B.Cu")
		(net "GND")
	)
	(via
		(at 302.448214 -251.716794)
		(size 0.4572)
		(drill 0.2032)
		(layers "F.Cu" "B.Cu")
		(net "GND")
	)
	(via
		(at 378.016262 -287.28924)
		(size 0.4572)
		(drill 0.2032)
		(layers "F.Cu" "B.Cu")
		(net "GND")
	)
	(via
		(at 212.724746 -273.816572)
		(size 0.4572)
		(drill 0.2032)
		(layers "F.Cu" "B.Cu")
		(net "GND")
	)
	(via
		(at 306.548282 -250.866656)
		(size 0.4572)
		(drill 0.2032)
		(layers "F.Cu" "B.Cu")
		(net "GND")
	)
	(via
		(at 457.221082 -238.116618)
		(size 0.4572)
		(drill 0.2032)
		(layers "F.Cu" "B.Cu")
		(net "GND")
	)
	(via
		(at 387.304534 -230.086662)
		(size 0.4572)
		(drill 0.2032)
		(layers "F.Cu" "B.Cu")
		(net "GND")
	)
	(via
		(at 438.033414 -270.416782)
		(size 0.4572)
		(drill 0.2032)
		(layers "F.Cu" "B.Cu")
		(net "GND")
	)
	(via
		(at 162.546284 -323.434456)
		(size 0.4572)
		(drill 0.2032)
		(layers "F.Cu" "B.Cu")
		(net "GND")
	)
	(via
		(at 296.794682 -261.066788)
		(size 0.4572)
		(drill 0.2032)
		(layers "F.Cu" "B.Cu")
		(net "GND")
	)
	(via
		(at 212.724746 -214.316564)
		(size 0.4572)
		(drill 0.2032)
		(layers "F.Cu" "B.Cu")
		(net "GND")
	)
	(via
		(at 443.367414 -267.016738)
		(size 0.4572)
		(drill 0.2032)
		(layers "F.Cu" "B.Cu")
		(net "GND")
	)
	(via
		(at 448.53098 -45.565568)
		(size 0.508)
		(drill 0.254)
		(layers "F.Cu" "B.Cu")
		(net "GND")
	)
	(via
		(at 356.761034 -216.25052)
		(size 0.4572)
		(drill 0.2032)
		(layers "F.Cu" "B.Cu")
		(net "GND")
	)
	(via
		(at 92.287598 -400.834352)
		(size 0.4064)
		(drill 0.2032)
		(layers "F.Cu" "B.Cu")
		(net "GND")
	)
	(via
		(at 136.545066 -243.108988)
		(size 0.4318)
		(drill 0.2032)
		(layers "F.Cu" "B.Cu")
		(net "GND")
	)
	(via
		(at 412.84398 -176.367948)
		(size 0.508)
		(drill 0.254)
		(layers "F.Cu" "B.Cu")
		(net "GND")
	)
	(via
		(at 254.975614 -238.966756)
		(size 0.4572)
		(drill 0.2032)
		(layers "F.Cu" "B.Cu")
		(net "GND")
	)
	(via
		(at 360.520234 -226.017328)
		(size 0.4572)
		(drill 0.2032)
		(layers "F.Cu" "B.Cu")
		(net "GND")
	)
	(via
		(at 312.928 -62.060328)
		(size 0.508)
		(drill 0.254)
		(layers "F.Cu" "B.Cu")
		(net "GND")
	)
	(via
		(at 343.243662 -284.033722)
		(size 0.4572)
		(drill 0.2032)
		(layers "F.Cu" "B.Cu")
		(net "GND")
	)
	(via
		(at 344.245692 -331.776832)
		(size 0.49022)
		(drill 0.254)
		(layers "F.Cu" "B.Cu")
		(net "GND")
	)
	(via
		(at 452.396352 -323.429376)
		(size 0.4572)
		(drill 0.2032)
		(layers "F.Cu" "B.Cu")
		(net "GND")
	)
	(via
		(at 417.292282 -196.466714)
		(size 0.4572)
		(drill 0.2032)
		(layers "F.Cu" "B.Cu")
		(net "GND")
	)
	(via
		(at 350.762316 -280.778204)
		(size 0.4572)
		(drill 0.2032)
		(layers "F.Cu" "B.Cu")
		(net "GND")
	)
	(via
		(at 294.904414 -238.966756)
		(size 0.4572)
		(drill 0.2032)
		(layers "F.Cu" "B.Cu")
		(net "GND")
	)
	(via
		(at 62.267846 -236.416596)
		(size 0.4572)
		(drill 0.2032)
		(layers "F.Cu" "B.Cu")
		(net "GND")
	)
	(via
		(at 310.207914 -287.416748)
		(size 0.4572)
		(drill 0.2032)
		(layers "F.Cu" "B.Cu")
		(net "GND")
	)
	(via
		(at 33.767014 -235.566712)
		(size 0.4572)
		(drill 0.2032)
		(layers "F.Cu" "B.Cu")
		(net "GND")
	)
	(via
		(at 176.896014 -272.966688)
		(size 0.4572)
		(drill 0.2032)
		(layers "F.Cu" "B.Cu")
		(net "GND")
	)
	(via
		(at 449.677282 -294.216582)
		(size 0.4572)
		(drill 0.2032)
		(layers "F.Cu" "B.Cu")
		(net "GND")
	)
	(via
		(at 445.577214 -233.016806)
		(size 0.4572)
		(drill 0.2032)
		(layers "F.Cu" "B.Cu")
		(net "GND")
	)
	(via
		(at 129.496312 -239.0394)
		(size 0.4572)
		(drill 0.2032)
		(layers "F.Cu" "B.Cu")
		(net "GND")
	)
	(via
		(at 181.73192 -353.19335)
		(size 0.49022)
		(drill 0.254)
		(layers "F.Cu" "B.Cu")
		(net "GND")
	)
	(via
		(at 72.258428 -144.665192)
		(size 0.508)
		(drill 0.254)
		(layers "F.Cu" "B.Cu")
		(net "GND")
	)
	(via
		(at 135.96366 -145.524728)
		(size 0.508)
		(drill 0.254)
		(layers "F.Cu" "B.Cu")
		(net "GND")
	)
	(via
		(at 184.919112 -25.899872)
		(size 0.508)
		(drill 0.254)
		(layers "F.Cu" "B.Cu")
		(net "GND")
	)
	(via
		(at 54.508146 -317.166752)
		(size 0.4572)
		(drill 0.2032)
		(layers "F.Cu" "B.Cu")
		(net "GND")
	)
	(via
		(at 169.267124 -17.655032)
		(size 0.508)
		(drill 0.254)
		(layers "F.Cu" "B.Cu")
		(net "GND")
	)
	(via
		(at 453.121014 -203.266802)
		(size 0.4572)
		(drill 0.2032)
		(layers "F.Cu" "B.Cu")
		(net "GND")
	)
	(via
		(at 147.349972 -432.747166)
		(size 0.4572)
		(drill 0.2032)
		(layers "F.Cu" "B.Cu")
		(net "GND")
	)
	(via
		(at 52.695094 -351.608644)
		(size 0.49022)
		(drill 0.254)
		(layers "F.Cu" "B.Cu")
		(net "GND")
	)
	(via
		(at 413.192214 -199.01662)
		(size 0.4572)
		(drill 0.2032)
		(layers "F.Cu" "B.Cu")
		(net "GND")
	)
	(via
		(at 358.280462 -287.28924)
		(size 0.4572)
		(drill 0.2032)
		(layers "F.Cu" "B.Cu")
		(net "GND")
	)
	(via
		(at 156.716222 -403.249892)
		(size 0.4572)
		(drill 0.254)
		(layers "F.Cu" "B.Cu")
		(net "GND")
	)
	(via
		(at 306.548282 -289.966654)
		(size 0.4572)
		(drill 0.2032)
		(layers "F.Cu" "B.Cu")
		(net "GND")
	)
	(via
		(at 282.71597 -436.457852)
		(size 0.508)
		(drill 0.254)
		(layers "F.Cu" "B.Cu")
		(net "GND")
	)
	(via
		(at 384.013964 -441.225432)
		(size 0.508)
		(drill 0.254)
		(layers "F.Cu" "B.Cu")
		(net "GND")
	)
	(via
		(at 370.51488 -40.096948)
		(size 0.508)
		(drill 0.254)
		(layers "F.Cu" "B.Cu")
		(net "GND")
	)
	(via
		(at 454.345802 -78.402434)
		(size 0.508)
		(drill 0.254)
		(layers "F.Cu" "B.Cu")
		(net "GND")
	)
	(via
		(at 123.027948 -278.336502)
		(size 0.4572)
		(drill 0.2032)
		(layers "F.Cu" "B.Cu")
		(net "GND")
	)
	(via
		(at 80.25003 -436.347362)
		(size 0.4572)
		(drill 0.2032)
		(layers "F.Cu" "B.Cu")
		(net "GND")
	)
	(via
		(at 363.656118 -359.94975)
		(size 0.508)
		(drill 0.254)
		(layers "F.Cu" "B.Cu")
		(net "GND")
	)
	(via
		(at 179.69992 -351.614994)
		(size 0.49022)
		(drill 0.254)
		(layers "F.Cu" "B.Cu")
		(net "GND")
	)
	(via
		(at 90.604848 -267.755878)
		(size 0.4572)
		(drill 0.2032)
		(layers "F.Cu" "B.Cu")
		(net "GND")
	)
	(via
		(at 33.767014 -222.816674)
		(size 0.4572)
		(drill 0.2032)
		(layers "F.Cu" "B.Cu")
		(net "GND")
	)
	(via
		(at 197.637146 -278.066754)
		(size 0.4572)
		(drill 0.2032)
		(layers "F.Cu" "B.Cu")
		(net "GND")
	)
	(via
		(at 377.076716 -275.8948)
		(size 0.4572)
		(drill 0.2032)
		(layers "F.Cu" "B.Cu")
		(net "GND")
	)
	(via
		(at 164.220906 -312.91657)
		(size 0.4572)
		(drill 0.2032)
		(layers "F.Cu" "B.Cu")
		(net "GND")
	)
	(via
		(at 123.994926 -123.112784)
		(size 0.508)
		(drill 0.254)
		(layers "F.Cu" "B.Cu")
		(net "GND")
	)
	(via
		(at 363.80928 -230.086662)
		(size 0.4572)
		(drill 0.2032)
		(layers "F.Cu" "B.Cu")
		(net "GND")
	)
	(via
		(at 7.035546 -225.36658)
		(size 0.4572)
		(drill 0.2032)
		(layers "F.Cu" "B.Cu")
		(net "GND")
	)
	(via
		(at 390.349994 -430.299622)
		(size 0.4572)
		(drill 0.2032)
		(layers "F.Cu" "B.Cu")
		(net "GND")
	)
	(via
		(at 140.941806 -407.638504)
		(size 0.4572)
		(drill 0.254)
		(layers "F.Cu" "B.Cu")
		(net "GND")
	)
	(via
		(at 48.854614 -310.366664)
		(size 0.4572)
		(drill 0.2032)
		(layers "F.Cu" "B.Cu")
		(net "GND")
	)
	(via
		(at 30.56509 -19.770344)
		(size 0.508)
		(drill 0.254)
		(layers "F.Cu" "B.Cu")
		(net "GND")
	)
	(via
		(at 365.406686 -12.544552)
		(size 0.508)
		(drill 0.254)
		(layers "F.Cu" "B.Cu")
		(net "GND")
	)
	(via
		(at 214.615014 -314.616592)
		(size 0.4572)
		(drill 0.2032)
		(layers "F.Cu" "B.Cu")
		(net "GND")
	)
	(via
		(at 98.013012 -231.714548)
		(size 0.4572)
		(drill 0.2032)
		(layers "F.Cu" "B.Cu")
		(net "GND")
	)
	(via
		(at 315.674248 -403.883876)
		(size 0.4064)
		(drill 0.2032)
		(layers "F.Cu" "B.Cu")
		(net "GND")
	)
	(via
		(at 26.223214 -247.466612)
		(size 0.4572)
		(drill 0.2032)
		(layers "F.Cu" "B.Cu")
		(net "GND")
	)
	(via
		(at 334.317848 -407.00452)
		(size 0.4064)
		(drill 0.2032)
		(layers "F.Cu" "B.Cu")
		(net "GND")
	)
	(via
		(at 409.243022 -404.51786)
		(size 0.4572)
		(drill 0.254)
		(layers "F.Cu" "B.Cu")
		(net "GND")
	)
	(via
		(at 22.123146 -201.56678)
		(size 0.4572)
		(drill 0.2032)
		(layers "F.Cu" "B.Cu")
		(net "GND")
	)
	(via
		(at 405.648414 -220.266768)
		(size 0.4572)
		(drill 0.2032)
		(layers "F.Cu" "B.Cu")
		(net "GND")
	)
	(via
		(at 20.889214 -205.816708)
		(size 0.4572)
		(drill 0.2032)
		(layers "F.Cu" "B.Cu")
		(net "GND")
	)
	(via
		(at 59.842146 -199.01662)
		(size 0.4572)
		(drill 0.2032)
		(layers "F.Cu" "B.Cu")
		(net "GND")
	)
	(via
		(at 338.250022 -428.851314)
		(size 0.4572)
		(drill 0.2032)
		(layers "F.Cu" "B.Cu")
		(net "GND")
	)
	(via
		(at 347.940884 -71.081392)
		(size 0.508)
		(drill 0.254)
		(layers "F.Cu" "B.Cu")
		(net "GND")
	)
	(via
		(at 390.950958 -407.638504)
		(size 0.4572)
		(drill 0.254)
		(layers "F.Cu" "B.Cu")
		(net "GND")
	)
	(via
		(at 16.789146 -242.3668)
		(size 0.4572)
		(drill 0.2032)
		(layers "F.Cu" "B.Cu")
		(net "GND")
	)
	(via
		(at 28.433014 -222.816674)
		(size 0.4572)
		(drill 0.2032)
		(layers "F.Cu" "B.Cu")
		(net "GND")
	)
	(via
		(at 116.9162 -77.130148)
		(size 0.508)
		(drill 0.254)
		(layers "F.Cu" "B.Cu")
		(net "GND")
	)
	(via
		(at 33.58515 -129.633472)
		(size 0.508)
		(drill 0.254)
		(layers "F.Cu" "B.Cu")
		(net "GND")
	)
	(via
		(at 7.035546 -231.316784)
		(size 0.4572)
		(drill 0.2032)
		(layers "F.Cu" "B.Cu")
		(net "GND")
	)
	(via
		(at 289.250882 -196.466714)
		(size 0.4572)
		(drill 0.2032)
		(layers "F.Cu" "B.Cu")
		(net "GND")
	)
	(via
		(at 382.99644 -63.447168)
		(size 0.508)
		(drill 0.254)
		(layers "F.Cu" "B.Cu")
		(net "GND")
	)
	(via
		(at 33.767014 -280.61666)
		(size 0.4572)
		(drill 0.2032)
		(layers "F.Cu" "B.Cu")
		(net "GND")
	)
	(via
		(at 365.683038 -201.20991)
		(size 0.6604)
		(drill 0.3302)
		(layers "F.Cu" "B.Cu")
		(net "GND")
	)
	(via
		(at 450.084952 -392.971274)
		(size 0.6604)
		(drill 0.3302)
		(layers "F.Cu" "B.Cu")
		(net "GND")
	)
	(via
		(at 430.489614 -234.716574)
		(size 0.4572)
		(drill 0.2032)
		(layers "F.Cu" "B.Cu")
		(net "GND")
	)
	(via
		(at 132.350002 -430.147222)
		(size 0.4572)
		(drill 0.2032)
		(layers "F.Cu" "B.Cu")
		(net "GND")
	)
	(via
		(at 439.923682 -228.766624)
		(size 0.4572)
		(drill 0.2032)
		(layers "F.Cu" "B.Cu")
		(net "GND")
	)
	(via
		(at 11.135614 -282.316682)
		(size 0.4572)
		(drill 0.2032)
		(layers "F.Cu" "B.Cu")
		(net "GND")
	)
	(via
		(at 90.024966 -216.25052)
		(size 0.4572)
		(drill 0.2032)
		(layers "F.Cu" "B.Cu")
		(net "GND")
	)
	(via
		(at 201.737214 -245.76659)
		(size 0.4572)
		(drill 0.2032)
		(layers "F.Cu" "B.Cu")
		(net "GND")
	)
	(via
		(at 257.185414 -258.516628)
		(size 0.4572)
		(drill 0.2032)
		(layers "F.Cu" "B.Cu")
		(net "GND")
	)
	(via
		(at 31.307278 -139.066524)
		(size 0.508)
		(drill 0.254)
		(layers "F.Cu" "B.Cu")
		(net "GND")
	)
	(via
		(at 423.52087 -354.182172)
		(size 0.508)
		(drill 0.254)
		(layers "F.Cu" "B.Cu")
		(net "GND")
	)
	(via
		(at 214.615014 -271.266666)
		(size 0.4572)
		(drill 0.2032)
		(layers "F.Cu" "B.Cu")
		(net "GND")
	)
	(via
		(at 105.179622 -239.292892)
		(size 0.4572)
		(drill 0.2032)
		(layers "F.Cu" "B.Cu")
		(net "GND")
	)
	(via
		(at 126.207266 -228.45903)
		(size 0.4572)
		(drill 0.2032)
		(layers "F.Cu" "B.Cu")
		(net "GND")
	)
	(via
		(at 137.484866 -221.94774)
		(size 0.4572)
		(drill 0.2032)
		(layers "F.Cu" "B.Cu")
		(net "GND")
	)
	(via
		(at 291.460682 -230.466646)
		(size 0.4572)
		(drill 0.2032)
		(layers "F.Cu" "B.Cu")
		(net "GND")
	)
	(via
		(at 427.826424 -120.97766)
		(size 0.508)
		(drill 0.254)
		(layers "F.Cu" "B.Cu")
		(net "GND")
	)
	(via
		(at 88.725248 -272.639282)
		(size 0.4572)
		(drill 0.2032)
		(layers "F.Cu" "B.Cu")
		(net "GND")
	)
	(via
		(at 360.566716 -332.56601)
		(size 0.49022)
		(drill 0.254)
		(layers "F.Cu" "B.Cu")
		(net "GND")
	)
	(via
		(at 70.571106 -410.664152)
		(size 0.4572)
		(drill 0.254)
		(layers "F.Cu" "B.Cu")
		(net "GND")
	)
	(via
		(at 82.824066 -410.664152)
		(size 0.4572)
		(drill 0.254)
		(layers "F.Cu" "B.Cu")
		(net "GND")
	)
	(via
		(at 304.338482 -299.316648)
		(size 0.4572)
		(drill 0.2032)
		(layers "F.Cu" "B.Cu")
		(net "GND")
	)
	(via
		(at 294.904414 -263.616694)
		(size 0.4572)
		(drill 0.2032)
		(layers "F.Cu" "B.Cu")
		(net "GND")
	)
	(via
		(at 415.73069 -400.834352)
		(size 0.4064)
		(drill 0.2032)
		(layers "F.Cu" "B.Cu")
		(net "GND")
	)
	(via
		(at 430.489614 -304.416714)
		(size 0.4572)
		(drill 0.2032)
		(layers "F.Cu" "B.Cu")
		(net "GND")
	)
	(via
		(at 254.975614 -233.016806)
		(size 0.4572)
		(drill 0.2032)
		(layers "F.Cu" "B.Cu")
		(net "GND")
	)
	(via
		(at 344.183462 -264.50036)
		(size 0.4572)
		(drill 0.2032)
		(layers "F.Cu" "B.Cu")
		(net "GND")
	)
	(via
		(at 122.557794 -287.28924)
		(size 0.4572)
		(drill 0.2032)
		(layers "F.Cu" "B.Cu")
		(net "GND")
	)
	(via
		(at 329.25004 -432.451256)
		(size 0.4572)
		(drill 0.2032)
		(layers "F.Cu" "B.Cu")
		(net "GND")
	)
	(via
		(at 390.78154 -341.983568)
		(size 0.508)
		(drill 0.254)
		(layers "F.Cu" "B.Cu")
		(net "GND")
	)
	(via
		(at 414.01365 -410.030168)
		(size 0.4064)
		(drill 0.2032)
		(layers "F.Cu" "B.Cu")
		(net "GND")
	)
	(via
		(at 335.615534 -221.94774)
		(size 0.4572)
		(drill 0.2032)
		(layers "F.Cu" "B.Cu")
		(net "GND")
	)
	(via
		(at 60.468002 -9.439148)
		(size 0.508)
		(drill 0.254)
		(layers "F.Cu" "B.Cu")
		(net "GND")
	)
	(via
		(at 50.302414 -345.64066)
		(size 0.508)
		(drill 0.254)
		(layers "F.Cu" "B.Cu")
		(net "GND")
	)
	(via
		(at 457.221082 -221.116652)
		(size 0.4572)
		(drill 0.2032)
		(layers "F.Cu" "B.Cu")
		(net "GND")
	)
	(via
		(at 329.25004 -431.29962)
		(size 0.4572)
		(drill 0.2032)
		(layers "F.Cu" "B.Cu")
		(net "GND")
	)
	(via
		(at 311.666382 -303.566576)
		(size 0.4572)
		(drill 0.2032)
		(layers "F.Cu" "B.Cu")
		(net "GND")
	)
	(via
		(at 191.983614 -204.116686)
		(size 0.4572)
		(drill 0.2032)
		(layers "F.Cu" "B.Cu")
		(net "GND")
	)
	(via
		(at 438.033414 -250.016772)
		(size 0.4572)
		(drill 0.2032)
		(layers "F.Cu" "B.Cu")
		(net "GND")
	)
	(via
		(at 129.147062 -404.51786)
		(size 0.4572)
		(drill 0.254)
		(layers "F.Cu" "B.Cu")
		(net "GND")
	)
	(via
		(at 214.615014 -247.466612)
		(size 0.4572)
		(drill 0.2032)
		(layers "F.Cu" "B.Cu")
		(net "GND")
	)
	(via
		(at 361.460034 -226.017328)
		(size 0.4572)
		(drill 0.2032)
		(layers "F.Cu" "B.Cu")
		(net "GND")
	)
	(via
		(at 259.89788 -47.643796)
		(size 0.508)
		(drill 0.254)
		(layers "F.Cu" "B.Cu")
		(net "GND")
	)
	(via
		(at 29.666946 -240.666778)
		(size 0.4572)
		(drill 0.2032)
		(layers "F.Cu" "B.Cu")
		(net "GND")
	)
	(via
		(at 28.433014 -207.51673)
		(size 0.4572)
		(drill 0.2032)
		(layers "F.Cu" "B.Cu")
		(net "GND")
	)
	(via
		(at 327.927208 -400.858228)
		(size 0.4064)
		(drill 0.2032)
		(layers "F.Cu" "B.Cu")
		(net "GND")
	)
	(via
		(at 106.471466 -230.086662)
		(size 0.4572)
		(drill 0.2032)
		(layers "F.Cu" "B.Cu")
		(net "GND")
	)
	(via
		(at 274.163282 -224.516696)
		(size 0.4572)
		(drill 0.2032)
		(layers "F.Cu" "B.Cu")
		(net "GND")
	)
	(via
		(at 353.117404 -333.355188)
		(size 0.49022)
		(drill 0.254)
		(layers "F.Cu" "B.Cu")
		(net "GND")
	)
	(via
		(at 449.677282 -232.166668)
		(size 0.4572)
		(drill 0.2032)
		(layers "F.Cu" "B.Cu")
		(net "GND")
	)
	(via
		(at 214.615014 -232.166668)
		(size 0.4572)
		(drill 0.2032)
		(layers "F.Cu" "B.Cu")
		(net "GND")
	)
	(via
		(at 339.644736 -331.852524)
		(size 0.508)
		(drill 0.254)
		(layers "F.Cu" "B.Cu")
		(net "GND")
	)
	(via
		(at 66.152014 -294.216582)
		(size 0.4572)
		(drill 0.2032)
		(layers "F.Cu" "B.Cu")
		(net "GND")
	)
	(via
		(at 11.135614 -258.516628)
		(size 0.4572)
		(drill 0.2032)
		(layers "F.Cu" "B.Cu")
		(net "GND")
	)
	(via
		(at 28.433014 -204.116686)
		(size 0.4572)
		(drill 0.2032)
		(layers "F.Cu" "B.Cu")
		(net "GND")
	)
	(via
		(at 453.121014 -281.466798)
		(size 0.4572)
		(drill 0.2032)
		(layers "F.Cu" "B.Cu")
		(net "GND")
	)
	(via
		(at 95.663766 -222.761556)
		(size 0.4572)
		(drill 0.2032)
		(layers "F.Cu" "B.Cu")
		(net "GND")
	)
	(via
		(at 122.923554 -410.030168)
		(size 0.4064)
		(drill 0.2032)
		(layers "F.Cu" "B.Cu")
		(net "GND")
	)
	(via
		(at 56.874918 -410.030168)
		(size 0.4064)
		(drill 0.2032)
		(layers "F.Cu" "B.Cu")
		(net "GND")
	)
	(via
		(at 22.123146 -304.416714)
		(size 0.4572)
		(drill 0.2032)
		(layers "F.Cu" "B.Cu")
		(net "GND")
	)
	(via
		(at 205.180946 -210.916774)
		(size 0.4572)
		(drill 0.2032)
		(layers "F.Cu" "B.Cu")
		(net "GND")
	)
	(via
		(at 458.455014 -227.066602)
		(size 0.4572)
		(drill 0.2032)
		(layers "F.Cu" "B.Cu")
		(net "GND")
	)
	(via
		(at 417.062412 -19.125438)
		(size 0.508)
		(drill 0.254)
		(layers "F.Cu" "B.Cu")
		(net "GND")
	)
	(via
		(at 186.649614 -244.066568)
		(size 0.4572)
		(drill 0.2032)
		(layers "F.Cu" "B.Cu")
		(net "GND")
	)
	(via
		(at 294.904414 -246.616728)
		(size 0.4572)
		(drill 0.2032)
		(layers "F.Cu" "B.Cu")
		(net "GND")
	)
	(via
		(at 176.896014 -222.816674)
		(size 0.4572)
		(drill 0.2032)
		(layers "F.Cu" "B.Cu")
		(net "GND")
	)
	(via
		(at 20.22729 -182.359046)
		(size 0.508)
		(drill 0.254)
		(layers "F.Cu" "B.Cu")
		(net "GND")
	)
	(via
		(at 332.144624 -336.982816)
		(size 0.508)
		(drill 0.254)
		(layers "F.Cu" "B.Cu")
		(net "GND")
	)
	(via
		(at 16.789146 -300.166786)
		(size 0.4572)
		(drill 0.2032)
		(layers "F.Cu" "B.Cu")
		(net "GND")
	)
	(via
		(at 24.332946 -242.3668)
		(size 0.4572)
		(drill 0.2032)
		(layers "F.Cu" "B.Cu")
		(net "GND")
	)
	(via
		(at 136.545066 -238.225584)
		(size 0.4318)
		(drill 0.2032)
		(layers "F.Cu" "B.Cu")
		(net "GND")
	)
	(via
		(at 344.25001 -432.747166)
		(size 0.4572)
		(drill 0.2032)
		(layers "F.Cu" "B.Cu")
		(net "GND")
	)
	(via
		(at 91.074494 -257.175254)
		(size 0.4572)
		(drill 0.2032)
		(layers "F.Cu" "B.Cu")
		(net "GND")
	)
	(via
		(at 247.596914 -86.35746)
		(size 0.508)
		(drill 0.254)
		(layers "F.Cu" "B.Cu")
		(net "GND")
	)
	(via
		(at 176.238154 -350.754188)
		(size 0.508)
		(drill 0.254)
		(layers "F.Cu" "B.Cu")
		(net "GND")
	)
	(via
		(at 415.919412 -367.0681)
		(size 0.508)
		(drill 0.254)
		(layers "F.Cu" "B.Cu")
		(net "GND")
	)
	(via
		(at 384.485134 -218.692222)
		(size 0.4572)
		(drill 0.2032)
		(layers "F.Cu" "B.Cu")
		(net "GND")
	)
	(via
		(at 172.795946 -206.666592)
		(size 0.4572)
		(drill 0.2032)
		(layers "F.Cu" "B.Cu")
		(net "GND")
	)
	(via
		(at 59.842146 -309.51678)
		(size 0.4572)
		(drill 0.2032)
		(layers "F.Cu" "B.Cu")
		(net "GND")
	)
	(via
		(at 134.195566 -219.506038)
		(size 0.4572)
		(drill 0.2032)
		(layers "F.Cu" "B.Cu")
		(net "GND")
	)
	(via
		(at 63.942214 -241.516662)
		(size 0.4572)
		(drill 0.2032)
		(layers "F.Cu" "B.Cu")
		(net "GND")
	)
	(via
		(at 123.027948 -281.59202)
		(size 0.4572)
		(drill 0.2032)
		(layers "F.Cu" "B.Cu")
		(net "GND")
	)
	(via
		(at 341.80018 -403.249892)
		(size 0.4572)
		(drill 0.254)
		(layers "F.Cu" "B.Cu")
		(net "GND")
	)
	(via
		(at 427.045882 -294.216582)
		(size 0.4572)
		(drill 0.2032)
		(layers "F.Cu" "B.Cu")
		(net "GND")
	)
	(via
		(at 63.942214 -294.216582)
		(size 0.4572)
		(drill 0.2032)
		(layers "F.Cu" "B.Cu")
		(net "GND")
	)
	(via
		(at 266.619482 -202.416664)
		(size 0.4572)
		(drill 0.2032)
		(layers "F.Cu" "B.Cu")
		(net "GND")
	)
	(via
		(at 354.539804 -331.776832)
		(size 0.49022)
		(drill 0.254)
		(layers "F.Cu" "B.Cu")
		(net "GND")
	)
	(via
		(at 118.582694 -239.306608)
		(size 0.4572)
		(drill 0.2032)
		(layers "F.Cu" "B.Cu")
		(net "GND")
	)
	(via
		(at 122.557794 -261.244842)
		(size 0.4572)
		(drill 0.2032)
		(layers "F.Cu" "B.Cu")
		(net "GND")
	)
	(via
		(at 368.70132 -413.50946)
		(size 0.508)
		(drill 0.254)
		(layers "F.Cu" "B.Cu")
		(net "GND")
	)
	(via
		(at 16.789146 -306.116736)
		(size 0.4572)
		(drill 0.2032)
		(layers "F.Cu" "B.Cu")
		(net "GND")
	)
	(via
		(at 123.497594 -287.28924)
		(size 0.4572)
		(drill 0.2032)
		(layers "F.Cu" "B.Cu")
		(net "GND")
	)
	(via
		(at 100.362766 -232.528364)
		(size 0.4572)
		(drill 0.2032)
		(layers "F.Cu" "B.Cu")
		(net "GND")
	)
	(via
		(at 48.854614 -278.916638)
		(size 0.4572)
		(drill 0.2032)
		(layers "F.Cu" "B.Cu")
		(net "GND")
	)
	(via
		(at 435.823614 -295.06672)
		(size 0.4572)
		(drill 0.2032)
		(layers "F.Cu" "B.Cu")
		(net "GND")
	)
	(via
		(at 287.360614 -208.366614)
		(size 0.4572)
		(drill 0.2032)
		(layers "F.Cu" "B.Cu")
		(net "GND")
	)
	(via
		(at 427.045882 -226.216718)
		(size 0.4572)
		(drill 0.2032)
		(layers "F.Cu" "B.Cu")
		(net "GND")
	)
	(via
		(at 276.373082 -216.866724)
		(size 0.4572)
		(drill 0.2032)
		(layers "F.Cu" "B.Cu")
		(net "GND")
	)
	(via
		(at 296.794682 -286.56661)
		(size 0.4572)
		(drill 0.2032)
		(layers "F.Cu" "B.Cu")
		(net "GND")
	)
	(via
		(at 314.092082 -267.866622)
		(size 0.4572)
		(drill 0.2032)
		(layers "F.Cu" "B.Cu")
		(net "GND")
	)
	(via
		(at 164.018214 -275.516594)
		(size 0.4572)
		(drill 0.2032)
		(layers "F.Cu" "B.Cu")
		(net "GND")
	)
	(via
		(at 450.911214 -227.066602)
		(size 0.4572)
		(drill 0.2032)
		(layers "F.Cu" "B.Cu")
		(net "GND")
	)
	(via
		(at 272.273014 -290.816792)
		(size 0.4572)
		(drill 0.2032)
		(layers "F.Cu" "B.Cu")
		(net "GND")
	)
	(via
		(at 340.424516 -257.98907)
		(size 0.4572)
		(drill 0.2032)
		(layers "F.Cu" "B.Cu")
		(net "GND")
	)
	(via
		(at 168.412922 -418.479478)
		(size 0.508)
		(drill 0.254)
		(layers "F.Cu" "B.Cu")
		(net "GND")
	)
	(via
		(at 43.520614 -245.76659)
		(size 0.4572)
		(drill 0.2032)
		(layers "F.Cu" "B.Cu")
		(net "GND")
	)
	(via
		(at 46.79061 -345.712288)
		(size 0.508)
		(drill 0.254)
		(layers "F.Cu" "B.Cu")
		(net "GND")
	)
	(via
		(at 133.255766 -242.294918)
		(size 0.4572)
		(drill 0.2032)
		(layers "F.Cu" "B.Cu")
		(net "GND")
	)
	(via
		(at 168.510966 -409.396184)
		(size 0.4572)
		(drill 0.254)
		(layers "F.Cu" "B.Cu")
		(net "GND")
	)
	(via
		(at 378.610622 -401.492212)
		(size 0.4572)
		(drill 0.254)
		(layers "F.Cu" "B.Cu")
		(net "GND")
	)
	(via
		(at 215.098884 -32.274256)
		(size 0.508)
		(drill 0.254)
		(layers "F.Cu" "B.Cu")
		(net "GND")
	)
	(via
		(at 260.790182 -69.231256)
		(size 0.508)
		(drill 0.254)
		(layers "F.Cu" "B.Cu")
		(net "GND")
	)
	(via
		(at 340.784434 -235.783882)
		(size 0.4572)
		(drill 0.2032)
		(layers "F.Cu" "B.Cu")
		(net "GND")
	)
	(via
		(at 294.904414 -281.466798)
		(size 0.4572)
		(drill 0.2032)
		(layers "F.Cu" "B.Cu")
		(net "GND")
	)
	(via
		(at 259.399786 -106.819192)
		(size 0.508)
		(drill 0.254)
		(layers "F.Cu" "B.Cu")
		(net "GND")
	)
	(via
		(at 96.243394 -264.50036)
		(size 0.4572)
		(drill 0.2032)
		(layers "F.Cu" "B.Cu")
		(net "GND")
	)
	(via
		(at 207.071214 -312.91657)
		(size 0.4572)
		(drill 0.2032)
		(layers "F.Cu" "B.Cu")
		(net "GND")
	)
	(via
		(at 69.224906 -404.51786)
		(size 0.4572)
		(drill 0.254)
		(layers "F.Cu" "B.Cu")
		(net "GND")
	)
	(via
		(at 143.34998 -437.49976)
		(size 0.4572)
		(drill 0.2032)
		(layers "F.Cu" "B.Cu")
		(net "GND")
	)
	(via
		(at 182.549546 -242.3668)
		(size 0.4572)
		(drill 0.2032)
		(layers "F.Cu" "B.Cu")
		(net "GND")
	)
	(via
		(at 23.946866 -9.424924)
		(size 0.508)
		(drill 0.254)
		(layers "F.Cu" "B.Cu")
		(net "GND")
	)
	(via
		(at 39.420546 -227.066602)
		(size 0.4572)
		(drill 0.2032)
		(layers "F.Cu" "B.Cu")
		(net "GND")
	)
	(via
		(at 123.020582 -404.51786)
		(size 0.4572)
		(drill 0.254)
		(layers "F.Cu" "B.Cu")
		(net "GND")
	)
	(via
		(at 39.420546 -225.36658)
		(size 0.4572)
		(drill 0.2032)
		(layers "F.Cu" "B.Cu")
		(net "GND")
	)
	(via
		(at 182.549546 -301.866808)
		(size 0.4572)
		(drill 0.2032)
		(layers "F.Cu" "B.Cu")
		(net "GND")
	)
	(via
		(at 363.448092 -331.780896)
		(size 0.49022)
		(drill 0.254)
		(layers "F.Cu" "B.Cu")
		(net "GND")
	)
	(via
		(at 453.121014 -261.916672)
		(size 0.4572)
		(drill 0.2032)
		(layers "F.Cu" "B.Cu")
		(net "GND")
	)
	(via
		(at 210.514946 -260.21665)
		(size 0.4572)
		(drill 0.2032)
		(layers "F.Cu" "B.Cu")
		(net "GND")
	)
	(via
		(at 14.579346 -234.716574)
		(size 0.4572)
		(drill 0.2032)
		(layers "F.Cu" "B.Cu")
		(net "GND")
	)
	(via
		(at 34.504884 -323.434456)
		(size 0.4572)
		(drill 0.2032)
		(layers "F.Cu" "B.Cu")
		(net "GND")
	)
	(via
		(at 22.123146 -260.21665)
		(size 0.4572)
		(drill 0.2032)
		(layers "F.Cu" "B.Cu")
		(net "GND")
	)
	(via
		(at 304.122582 -314.616592)
		(size 0.4572)
		(drill 0.2032)
		(layers "F.Cu" "B.Cu")
		(net "GND")
	)
	(via
		(at 276.373082 -271.266666)
		(size 0.4572)
		(drill 0.2032)
		(layers "F.Cu" "B.Cu")
		(net "GND")
	)
	(via
		(at 254.975614 -276.366732)
		(size 0.4572)
		(drill 0.2032)
		(layers "F.Cu" "B.Cu")
		(net "GND")
	)
	(via
		(at 164.221414 -272.966688)
		(size 0.4572)
		(drill 0.2032)
		(layers "F.Cu" "B.Cu")
		(net "GND")
	)
	(via
		(at 90.667586 -401.492212)
		(size 0.4572)
		(drill 0.254)
		(layers "F.Cu" "B.Cu")
		(net "GND")
	)
	(via
		(at 112.580166 -226.017328)
		(size 0.4572)
		(drill 0.2032)
		(layers "F.Cu" "B.Cu")
		(net "GND")
	)
	(via
		(at 428.279814 -315.46673)
		(size 0.4572)
		(drill 0.2032)
		(layers "F.Cu" "B.Cu")
		(net "GND")
	)
	(via
		(at 123.66879 -331.780896)
		(size 0.49022)
		(drill 0.254)
		(layers "F.Cu" "B.Cu")
		(net "GND")
	)
	(via
		(at 372.21033 -407.00452)
		(size 0.4064)
		(drill 0.2032)
		(layers "F.Cu" "B.Cu")
		(net "GND")
	)
	(via
		(at 47.360078 -98.824034)
		(size 0.508)
		(drill 0.254)
		(layers "F.Cu" "B.Cu")
		(net "GND")
	)
	(via
		(at 125.808486 -330.214732)
		(size 0.508)
		(drill 0.254)
		(layers "F.Cu" "B.Cu")
		(net "GND")
	)
	(via
		(at 92.844366 -248.806208)
		(size 0.4572)
		(drill 0.2032)
		(layers "F.Cu" "B.Cu")
		(net "GND")
	)
	(via
		(at 272.273014 -261.916672)
		(size 0.4572)
		(drill 0.2032)
		(layers "F.Cu" "B.Cu")
		(net "GND")
	)
	(via
		(at 382.135634 -227.64496)
		(size 0.4572)
		(drill 0.2032)
		(layers "F.Cu" "B.Cu")
		(net "GND")
	)
	(via
		(at 13.345414 -297.616626)
		(size 0.4572)
		(drill 0.2032)
		(layers "F.Cu" "B.Cu")
		(net "GND")
	)
	(via
		(at 167.461946 -231.316784)
		(size 0.4572)
		(drill 0.2032)
		(layers "F.Cu" "B.Cu")
		(net "GND")
	)
	(via
		(at 35.976814 -262.76681)
		(size 0.4572)
		(drill 0.2032)
		(layers "F.Cu" "B.Cu")
		(net "GND")
	)
	(via
		(at 111.306102 -332.56601)
		(size 0.49022)
		(drill 0.254)
		(layers "F.Cu" "B.Cu")
		(net "GND")
	)
	(via
		(at 333.235808 -335.77403)
		(size 0.508)
		(drill 0.254)
		(layers "F.Cu" "B.Cu")
		(net "GND")
	)
	(via
		(at 287.360614 -216.016586)
		(size 0.4572)
		(drill 0.2032)
		(layers "F.Cu" "B.Cu")
		(net "GND")
	)
	(via
		(at 157.708346 -290.816792)
		(size 0.4572)
		(drill 0.2032)
		(layers "F.Cu" "B.Cu")
		(net "GND")
	)
	(via
		(at 352.697288 -407.00452)
		(size 0.4064)
		(drill 0.2032)
		(layers "F.Cu" "B.Cu")
		(net "GND")
	)
	(via
		(at 202.550522 -68.953126)
		(size 0.508)
		(drill 0.254)
		(layers "F.Cu" "B.Cu")
		(net "GND")
	)
	(via
		(at 375.557034 -226.017328)
		(size 0.4572)
		(drill 0.2032)
		(layers "F.Cu" "B.Cu")
		(net "GND")
	)
	(via
		(at 46.964346 -251.716794)
		(size 0.4572)
		(drill 0.2032)
		(layers "F.Cu" "B.Cu")
		(net "GND")
	)
	(via
		(at 320.718688 -400.858228)
		(size 0.4064)
		(drill 0.2032)
		(layers "F.Cu" "B.Cu")
		(net "GND")
	)
	(via
		(at 415.597848 -311.216802)
		(size 0.4572)
		(drill 0.2032)
		(layers "F.Cu" "B.Cu")
		(net "GND")
	)
	(via
		(at 171.562014 -289.966654)
		(size 0.4572)
		(drill 0.2032)
		(layers "F.Cu" "B.Cu")
		(net "GND")
	)
	(via
		(at 120.568212 -233.34218)
		(size 0.4572)
		(drill 0.2032)
		(layers "F.Cu" "B.Cu")
		(net "GND")
	)
	(via
		(at 99.187254 -332.570074)
		(size 0.49022)
		(drill 0.254)
		(layers "F.Cu" "B.Cu")
		(net "GND")
	)
	(via
		(at 161.808414 -258.516628)
		(size 0.4572)
		(drill 0.2032)
		(layers "F.Cu" "B.Cu")
		(net "GND")
	)
	(via
		(at 198.20636 -120.614948)
		(size 0.508)
		(drill 0.254)
		(layers "F.Cu" "B.Cu")
		(net "GND")
	)
	(via
		(at 186.649614 -216.866724)
		(size 0.4572)
		(drill 0.2032)
		(layers "F.Cu" "B.Cu")
		(net "GND")
	)
	(via
		(at 123.027948 -271.825212)
		(size 0.4572)
		(drill 0.2032)
		(layers "F.Cu" "B.Cu")
		(net "GND")
	)
	(via
		(at 123.027948 -283.219906)
		(size 0.4572)
		(drill 0.2032)
		(layers "F.Cu" "B.Cu")
		(net "GND")
	)
	(via
		(at 277.607014 -263.616694)
		(size 0.4572)
		(drill 0.2032)
		(layers "F.Cu" "B.Cu")
		(net "GND")
	)
	(via
		(at 264.729214 -276.366732)
		(size 0.4572)
		(drill 0.2032)
		(layers "F.Cu" "B.Cu")
		(net "GND")
	)
	(via
		(at 450.911214 -234.716574)
		(size 0.4572)
		(drill 0.2032)
		(layers "F.Cu" "B.Cu")
		(net "GND")
	)
	(via
		(at 435.823614 -298.466764)
		(size 0.4572)
		(drill 0.2032)
		(layers "F.Cu" "B.Cu")
		(net "GND")
	)
	(via
		(at 2.764536 -386.510022)
		(size 0.508)
		(drill 0.254)
		(layers "F.Cu" "B.Cu")
		(net "GND")
	)
	(via
		(at 58.065162 -160.22828)
		(size 0.508)
		(drill 0.254)
		(layers "F.Cu" "B.Cu")
		(net "GND")
	)
	(via
		(at 418.09543 -6.07949)
		(size 0.508)
		(drill 0.254)
		(layers "F.Cu" "B.Cu")
		(net "GND")
	)
	(via
		(at 311.882282 -299.316648)
		(size 0.4572)
		(drill 0.2032)
		(layers "F.Cu" "B.Cu")
		(net "GND")
	)
	(via
		(at 343.050368 -84.010246)
		(size 0.508)
		(drill 0.254)
		(layers "F.Cu" "B.Cu")
		(net "GND")
	)
	(via
		(at 352.280474 -167.888412)
		(size 0.508)
		(drill 0.254)
		(layers "F.Cu" "B.Cu")
		(net "GND")
	)
	(via
		(at 388.573772 -26.185622)
		(size 0.508)
		(drill 0.254)
		(layers "F.Cu" "B.Cu")
		(net "GND")
	)
	(via
		(at 94.79026 -111.338868)
		(size 0.508)
		(drill 0.254)
		(layers "F.Cu" "B.Cu")
		(net "GND")
	)
	(via
		(at 435.823614 -279.766776)
		(size 0.4572)
		(drill 0.2032)
		(layers "F.Cu" "B.Cu")
		(net "GND")
	)
	(via
		(at 371.189758 -360.132376)
		(size 0.508)
		(drill 0.254)
		(layers "F.Cu" "B.Cu")
		(net "GND")
	)
	(via
		(at 334.205834 -247.178322)
		(size 0.4572)
		(drill 0.2032)
		(layers "F.Cu" "B.Cu")
		(net "GND")
	)
	(via
		(at 24.332946 -283.166566)
		(size 0.4572)
		(drill 0.2032)
		(layers "F.Cu" "B.Cu")
		(net "GND")
	)
	(via
		(at 165.252146 -263.616694)
		(size 0.4572)
		(drill 0.2032)
		(layers "F.Cu" "B.Cu")
		(net "GND")
	)
	(via
		(at 294.325548 -163.135564)
		(size 0.508)
		(drill 0.254)
		(layers "F.Cu" "B.Cu")
		(net "GND")
	)
	(via
		(at 368.892582 -248.327926)
		(size 0.4572)
		(drill 0.2032)
		(layers "F.Cu" "B.Cu")
		(net "GND")
	)
	(via
		(at 182.549546 -227.066602)
		(size 0.4572)
		(drill 0.2032)
		(layers "F.Cu" "B.Cu")
		(net "GND")
	)
	(via
		(at 91.704922 -333.173324)
		(size 0.508)
		(drill 0.254)
		(layers "F.Cu" "B.Cu")
		(net "GND")
	)
	(via
		(at 319.25006 -427.851316)
		(size 0.4572)
		(drill 0.2032)
		(layers "F.Cu" "B.Cu")
		(net "GND")
	)
	(via
		(at 132.315966 -229.272846)
		(size 0.4572)
		(drill 0.2032)
		(layers "F.Cu" "B.Cu")
		(net "GND")
	)
	(via
		(at 407.858214 -197.316598)
		(size 0.4572)
		(drill 0.2032)
		(layers "F.Cu" "B.Cu")
		(net "GND")
	)
	(via
		(at 396.646908 -7.215124)
		(size 0.508)
		(drill 0.254)
		(layers "F.Cu" "B.Cu")
		(net "GND")
	)
	(via
		(at 304.122582 -275.516594)
		(size 0.4572)
		(drill 0.2032)
		(layers "F.Cu" "B.Cu")
		(net "GND")
	)
	(via
		(at 283.916882 -215.166702)
		(size 0.4572)
		(drill 0.2032)
		(layers "F.Cu" "B.Cu")
		(net "GND")
	)
	(via
		(at 157.708346 -315.46673)
		(size 0.4572)
		(drill 0.2032)
		(layers "F.Cu" "B.Cu")
		(net "GND")
	)
	(via
		(at 37.210746 -298.466764)
		(size 0.4572)
		(drill 0.2032)
		(layers "F.Cu" "B.Cu")
		(net "GND")
	)
	(via
		(at 417.292282 -241.516662)
		(size 0.4572)
		(drill 0.2032)
		(layers "F.Cu" "B.Cu")
		(net "GND")
	)
	(via
		(at 445.577214 -216.016586)
		(size 0.4572)
		(drill 0.2032)
		(layers "F.Cu" "B.Cu")
		(net "GND")
	)
	(via
		(at 164.018214 -261.066788)
		(size 0.4572)
		(drill 0.2032)
		(layers "F.Cu" "B.Cu")
		(net "GND")
	)
	(via
		(at 350.652334 -220.319854)
		(size 0.4572)
		(drill 0.2032)
		(layers "F.Cu" "B.Cu")
		(net "GND")
	)
	(via
		(at 171.24553 -433.923948)
		(size 0.508)
		(drill 0.254)
		(layers "F.Cu" "B.Cu")
		(net "GND")
	)
	(via
		(at 29.666946 -307.816758)
		(size 0.4572)
		(drill 0.2032)
		(layers "F.Cu" "B.Cu")
		(net "GND")
	)
	(via
		(at 175.355504 -110.175294)
		(size 0.4572)
		(drill 0.254)
		(layers "F.Cu" "B.Cu")
		(net "GND")
	)
	(via
		(at 97.543366 -239.0394)
		(size 0.4572)
		(drill 0.2032)
		(layers "F.Cu" "B.Cu")
		(net "GND")
	)
	(via
		(at 462.555082 -224.516696)
		(size 0.4572)
		(drill 0.2032)
		(layers "F.Cu" "B.Cu")
		(net "GND")
	)
	(via
		(at 332.250034 -437.49976)
		(size 0.4572)
		(drill 0.2032)
		(layers "F.Cu" "B.Cu")
		(net "GND")
	)
	(via
		(at 22.123146 -251.716794)
		(size 0.4572)
		(drill 0.2032)
		(layers "F.Cu" "B.Cu")
		(net "GND")
	)
	(via
		(at 266.619482 -228.766624)
		(size 0.4572)
		(drill 0.2032)
		(layers "F.Cu" "B.Cu")
		(net "GND")
	)
	(via
		(at 14.579346 -309.51678)
		(size 0.4572)
		(drill 0.2032)
		(layers "F.Cu" "B.Cu")
		(net "GND")
	)
	(via
		(at 389.903208 -336.779616)
		(size 0.508)
		(drill 0.254)
		(layers "F.Cu" "B.Cu")
		(net "GND")
	)
	(via
		(at 90.20937 -406.370536)
		(size 0.4572)
		(drill 0.254)
		(layers "F.Cu" "B.Cu")
		(net "GND")
	)
	(via
		(at 294.904414 -233.016806)
		(size 0.4572)
		(drill 0.2032)
		(layers "F.Cu" "B.Cu")
		(net "GND")
	)
	(via
		(at 352.3361 -409.396184)
		(size 0.4572)
		(drill 0.254)
		(layers "F.Cu" "B.Cu")
		(net "GND")
	)
	(via
		(at 22.123146 -278.066754)
		(size 0.4572)
		(drill 0.2032)
		(layers "F.Cu" "B.Cu")
		(net "GND")
	)
	(via
		(at 340.250018 -430.299622)
		(size 0.4572)
		(drill 0.2032)
		(layers "F.Cu" "B.Cu")
		(net "GND")
	)
	(via
		(at 187.883546 -201.56678)
		(size 0.4572)
		(drill 0.2032)
		(layers "F.Cu" "B.Cu")
		(net "GND")
	)
	(via
		(at 469.984074 -79.234284)
		(size 0.508)
		(drill 0.254)
		(layers "F.Cu" "B.Cu")
		(net "GND")
	)
	(via
		(at 165.252146 -204.96657)
		(size 0.4572)
		(drill 0.2032)
		(layers "F.Cu" "B.Cu")
		(net "GND")
	)
	(via
		(at 453.121014 -223.666558)
		(size 0.4572)
		(drill 0.2032)
		(layers "F.Cu" "B.Cu")
		(net "GND")
	)
	(via
		(at 207.071214 -262.76681)
		(size 0.4572)
		(drill 0.2032)
		(layers "F.Cu" "B.Cu")
		(net "GND")
	)
	(via
		(at 191.983614 -244.066568)
		(size 0.4572)
		(drill 0.2032)
		(layers "F.Cu" "B.Cu")
		(net "GND")
	)
	(via
		(at 379.786134 -249.620024)
		(size 0.4572)
		(drill 0.2032)
		(layers "F.Cu" "B.Cu")
		(net "GND")
	)
	(via
		(at 307.782214 -204.96657)
		(size 0.4572)
		(drill 0.2032)
		(layers "F.Cu" "B.Cu")
		(net "GND")
	)
	(via
		(at 378.84608 -230.086662)
		(size 0.4572)
		(drill 0.2032)
		(layers "F.Cu" "B.Cu")
		(net "GND")
	)
	(via
		(at 363.33938 -216.25052)
		(size 0.4572)
		(drill 0.2032)
		(layers "F.Cu" "B.Cu")
		(net "GND")
	)
	(via
		(at 66.367914 -271.266666)
		(size 0.4572)
		(drill 0.2032)
		(layers "F.Cu" "B.Cu")
		(net "GND")
	)
	(via
		(at 184.917842 -24.906732)
		(size 0.508)
		(drill 0.254)
		(layers "F.Cu" "B.Cu")
		(net "GND")
	)
	(via
		(at 299.004482 -244.066568)
		(size 0.4572)
		(drill 0.2032)
		(layers "F.Cu" "B.Cu")
		(net "GND")
	)
	(via
		(at 16.789146 -290.816792)
		(size 0.4572)
		(drill 0.2032)
		(layers "F.Cu" "B.Cu")
		(net "GND")
	)
	(via
		(at 190.093346 -246.616728)
		(size 0.4572)
		(drill 0.2032)
		(layers "F.Cu" "B.Cu")
		(net "GND")
	)
	(via
		(at 115.399566 -219.506038)
		(size 0.4572)
		(drill 0.2032)
		(layers "F.Cu" "B.Cu")
		(net "GND")
	)
	(via
		(at 152.489154 -117.312948)
		(size 0.508)
		(drill 0.254)
		(layers "F.Cu" "B.Cu")
		(net "GND")
	)
	(via
		(at 292.694614 -260.21665)
		(size 0.4572)
		(drill 0.2032)
		(layers "F.Cu" "B.Cu")
		(net "GND")
	)
	(via
		(at 431.619914 -136.526778)
		(size 0.508)
		(drill 0.254)
		(layers "F.Cu" "B.Cu")
		(net "GND")
	)
	(via
		(at 124.907548 -278.336502)
		(size 0.4572)
		(drill 0.2032)
		(layers "F.Cu" "B.Cu")
		(net "GND")
	)
	(via
		(at 18.679414 -289.966654)
		(size 0.4572)
		(drill 0.2032)
		(layers "F.Cu" "B.Cu")
		(net "GND")
	)
	(via
		(at 309.547768 -403.883876)
		(size 0.4064)
		(drill 0.2032)
		(layers "F.Cu" "B.Cu")
		(net "GND")
	)
	(via
		(at 458.455014 -220.266768)
		(size 0.4572)
		(drill 0.2032)
		(layers "F.Cu" "B.Cu")
		(net "GND")
	)
	(via
		(at 77.95641 -409.396184)
		(size 0.4572)
		(drill 0.254)
		(layers "F.Cu" "B.Cu")
		(net "GND")
	)
	(via
		(at 415.903664 -364.071662)
		(size 0.49022)
		(drill 0.254)
		(layers "F.Cu" "B.Cu")
		(net "GND")
	)
	(via
		(at 159.918146 -244.916706)
		(size 0.4572)
		(drill 0.2032)
		(layers "F.Cu" "B.Cu")
		(net "GND")
	)
	(via
		(at 398.794478 -404.51786)
		(size 0.4572)
		(drill 0.254)
		(layers "F.Cu" "B.Cu")
		(net "GND")
	)
	(via
		(at 306.548282 -200.716642)
		(size 0.4572)
		(drill 0.2032)
		(layers "F.Cu" "B.Cu")
		(net "GND")
	)
	(via
		(at 414.85947 -164.198554)
		(size 0.49022)
		(drill 0.254)
		(layers "F.Cu" "B.Cu")
		(net "GND")
	)
	(via
		(at 289.250882 -247.466612)
		(size 0.4572)
		(drill 0.2032)
		(layers "F.Cu" "B.Cu")
		(net "GND")
	)
	(via
		(at 373.317516 -284.033722)
		(size 0.4572)
		(drill 0.2032)
		(layers "F.Cu" "B.Cu")
		(net "GND")
	)
	(via
		(at 203.062332 -109.529118)
		(size 0.508)
		(drill 0.254)
		(layers "F.Cu" "B.Cu")
		(net "GND")
	)
	(via
		(at 31.876746 -261.916672)
		(size 0.4572)
		(drill 0.2032)
		(layers "F.Cu" "B.Cu")
		(net "GND")
	)
	(via
		(at 375.667016 -275.08073)
		(size 0.4572)
		(drill 0.2032)
		(layers "F.Cu" "B.Cu")
		(net "GND")
	)
	(via
		(at 195.446396 -19.14144)
		(size 0.508)
		(drill 0.254)
		(layers "F.Cu" "B.Cu")
		(net "GND")
	)
	(via
		(at 442.133482 -244.066568)
		(size 0.4572)
		(drill 0.2032)
		(layers "F.Cu" "B.Cu")
		(net "GND")
	)
	(via
		(at 171.562014 -198.166736)
		(size 0.4572)
		(drill 0.2032)
		(layers "F.Cu" "B.Cu")
		(net "GND")
	)
	(via
		(at 153.34996 -430.147222)
		(size 0.4572)
		(drill 0.2032)
		(layers "F.Cu" "B.Cu")
		(net "GND")
	)
	(via
		(at 297.95851 -49.320196)
		(size 0.508)
		(drill 0.254)
		(layers "F.Cu" "B.Cu")
		(net "GND")
	)
	(via
		(at 184.439814 -249.166634)
		(size 0.4572)
		(drill 0.2032)
		(layers "F.Cu" "B.Cu")
		(net "GND")
	)
	(via
		(at 304.338482 -308.666642)
		(size 0.4572)
		(drill 0.2032)
		(layers "F.Cu" "B.Cu")
		(net "GND")
	)
	(via
		(at 132.315712 -245.55069)
		(size 0.4572)
		(drill 0.2032)
		(layers "F.Cu" "B.Cu")
		(net "GND")
	)
	(via
		(at 22.31771 -181.456076)
		(size 0.508)
		(drill 0.254)
		(layers "F.Cu" "B.Cu")
		(net "GND")
	)
	(via
		(at 125.377448 -284.033722)
		(size 0.4572)
		(drill 0.2032)
		(layers "F.Cu" "B.Cu")
		(net "GND")
	)
	(via
		(at 69.250052 -434.899562)
		(size 0.4572)
		(drill 0.2032)
		(layers "F.Cu" "B.Cu")
		(net "GND")
	)
	(via
		(at 18.679414 -291.666676)
		(size 0.4572)
		(drill 0.2032)
		(layers "F.Cu" "B.Cu")
		(net "GND")
	)
	(via
		(at 410.95041 -410.030168)
		(size 0.4064)
		(drill 0.2032)
		(layers "F.Cu" "B.Cu")
		(net "GND")
	)
	(via
		(at 99.532948 -258.80314)
		(size 0.4572)
		(drill 0.2032)
		(layers "F.Cu" "B.Cu")
		(net "GND")
	)
	(via
		(at 156.258006 -409.396184)
		(size 0.4572)
		(drill 0.254)
		(layers "F.Cu" "B.Cu")
		(net "GND")
	)
	(via
		(at 376.496834 -247.178322)
		(size 0.4572)
		(drill 0.2032)
		(layers "F.Cu" "B.Cu")
		(net "GND")
	)
	(via
		(at 124.437394 -271.011396)
		(size 0.4572)
		(drill 0.2032)
		(layers "F.Cu" "B.Cu")
		(net "GND")
	)
	(via
		(at 118.328948 -283.219906)
		(size 0.4572)
		(drill 0.2032)
		(layers "F.Cu" "B.Cu")
		(net "GND")
	)
	(via
		(at 106.001566 -216.25052)
		(size 0.4572)
		(drill 0.2032)
		(layers "F.Cu" "B.Cu")
		(net "GND")
	)
	(via
		(at 42.193972 -351.608644)
		(size 0.49022)
		(drill 0.254)
		(layers "F.Cu" "B.Cu")
		(net "GND")
	)
	(via
		(at 335.42478 -335.187036)
		(size 0.49022)
		(drill 0.254)
		(layers "F.Cu" "B.Cu")
		(net "GND")
	)
	(via
		(at 430.489614 -236.416596)
		(size 0.4572)
		(drill 0.2032)
		(layers "F.Cu" "B.Cu")
		(net "GND")
	)
	(via
		(at 56.398414 -196.466714)
		(size 0.4572)
		(drill 0.2032)
		(layers "F.Cu" "B.Cu")
		(net "GND")
	)
	(via
		(at 106.06405 -250.33732)
		(size 0.4572)
		(drill 0.2032)
		(layers "F.Cu" "B.Cu")
		(net "GND")
	)
	(via
		(at 191.983614 -245.76659)
		(size 0.4572)
		(drill 0.2032)
		(layers "F.Cu" "B.Cu")
		(net "GND")
	)
	(via
		(at 239.99952 -57.174638)
		(size 0.508)
		(drill 0.254)
		(layers "F.Cu" "B.Cu")
		(net "GND")
	)
	(via
		(at 134.195566 -240.667286)
		(size 0.4572)
		(drill 0.2032)
		(layers "F.Cu" "B.Cu")
		(net "GND")
	)
	(via
		(at 169.352214 -306.96662)
		(size 0.4572)
		(drill 0.2032)
		(layers "F.Cu" "B.Cu")
		(net "GND")
	)
	(via
		(at 299.004482 -245.76659)
		(size 0.4572)
		(drill 0.2032)
		(layers "F.Cu" "B.Cu")
		(net "GND")
	)
	(via
		(at 214.615014 -249.166634)
		(size 0.4572)
		(drill 0.2032)
		(layers "F.Cu" "B.Cu")
		(net "GND")
	)
	(via
		(at 37.210746 -287.416748)
		(size 0.4572)
		(drill 0.2032)
		(layers "F.Cu" "B.Cu")
		(net "GND")
	)
	(via
		(at 262.519414 -295.06672)
		(size 0.4572)
		(drill 0.2032)
		(layers "F.Cu" "B.Cu")
		(net "GND")
	)
	(via
		(at 54.893718 -410.030168)
		(size 0.4064)
		(drill 0.2032)
		(layers "F.Cu" "B.Cu")
		(net "GND")
	)
	(via
		(at 197.637146 -315.46673)
		(size 0.4572)
		(drill 0.2032)
		(layers "F.Cu" "B.Cu")
		(net "GND")
	)
	(via
		(at 194.193414 -216.866724)
		(size 0.4572)
		(drill 0.2032)
		(layers "F.Cu" "B.Cu")
		(net "GND")
	)
	(via
		(at 281.707082 -291.666676)
		(size 0.4572)
		(drill 0.2032)
		(layers "F.Cu" "B.Cu")
		(net "GND")
	)
	(via
		(at 193.641472 -21.358352)
		(size 0.508)
		(drill 0.254)
		(layers "F.Cu" "B.Cu")
		(net "GND")
	)
	(via
		(at 358.280462 -280.778204)
		(size 0.4572)
		(drill 0.2032)
		(layers "F.Cu" "B.Cu")
		(net "GND")
	)
	(via
		(at 115.869212 -233.34218)
		(size 0.4572)
		(drill 0.2032)
		(layers "F.Cu" "B.Cu")
		(net "GND")
	)
	(via
		(at 303.782476 -404.51786)
		(size 0.4572)
		(drill 0.254)
		(layers "F.Cu" "B.Cu")
		(net "GND")
	)
	(via
		(at 442.133482 -289.966654)
		(size 0.4572)
		(drill 0.2032)
		(layers "F.Cu" "B.Cu")
		(net "GND")
	)
	(via
		(at 54.508146 -242.3668)
		(size 0.4572)
		(drill 0.2032)
		(layers "F.Cu" "B.Cu")
		(net "GND")
	)
	(via
		(at 125.737366 -229.272846)
		(size 0.4572)
		(drill 0.2032)
		(layers "F.Cu" "B.Cu")
		(net "GND")
	)
	(via
		(at 97.073466 -239.853216)
		(size 0.4572)
		(drill 0.2032)
		(layers "F.Cu" "B.Cu")
		(net "GND")
	)
	(via
		(at 405.648414 -210.916774)
		(size 0.4572)
		(drill 0.2032)
		(layers "F.Cu" "B.Cu")
		(net "GND")
	)
	(via
		(at 100.472494 -286.475424)
		(size 0.4572)
		(drill 0.2032)
		(layers "F.Cu" "B.Cu")
		(net "GND")
	)
	(via
		(at 384.015234 -230.900478)
		(size 0.4572)
		(drill 0.2032)
		(layers "F.Cu" "B.Cu")
		(net "GND")
	)
	(via
		(at 48.854614 -244.066568)
		(size 0.4572)
		(drill 0.2032)
		(layers "F.Cu" "B.Cu")
		(net "GND")
	)
	(via
		(at 43.520614 -310.366664)
		(size 0.4572)
		(drill 0.2032)
		(layers "F.Cu" "B.Cu")
		(net "GND")
	)
	(via
		(at 370.968016 -257.175254)
		(size 0.4572)
		(drill 0.2032)
		(layers "F.Cu" "B.Cu")
		(net "GND")
	)
	(via
		(at 411.52318 -167.071548)
		(size 0.508)
		(drill 0.254)
		(layers "F.Cu" "B.Cu")
		(net "GND")
	)
	(via
		(at 413.50438 -175.707548)
		(size 0.508)
		(drill 0.254)
		(layers "F.Cu" "B.Cu")
		(net "GND")
	)
	(via
		(at 460.664814 -258.516628)
		(size 0.4572)
		(drill 0.2032)
		(layers "F.Cu" "B.Cu")
		(net "GND")
	)
	(via
		(at 128.35001 -438.499758)
		(size 0.4572)
		(drill 0.2032)
		(layers "F.Cu" "B.Cu")
		(net "GND")
	)
	(via
		(at 373.830342 -406.370536)
		(size 0.4572)
		(drill 0.254)
		(layers "F.Cu" "B.Cu")
		(net "GND")
	)
	(via
		(at 274.163282 -216.866724)
		(size 0.4572)
		(drill 0.2032)
		(layers "F.Cu" "B.Cu")
		(net "GND")
	)
	(via
		(at 57.024524 -177.987452)
		(size 0.508)
		(drill 0.254)
		(layers "F.Cu" "B.Cu")
		(net "GND")
	)
	(via
		(at 15.353284 -323.434456)
		(size 0.4572)
		(drill 0.2032)
		(layers "F.Cu" "B.Cu")
		(net "GND")
	)
	(via
		(at 56.398414 -215.166702)
		(size 0.4572)
		(drill 0.2032)
		(layers "F.Cu" "B.Cu")
		(net "GND")
	)
	(via
		(at 184.439814 -258.516628)
		(size 0.4572)
		(drill 0.2032)
		(layers "F.Cu" "B.Cu")
		(net "GND")
	)
	(via
		(at 31.876746 -289.11677)
		(size 0.4572)
		(drill 0.2032)
		(layers "F.Cu" "B.Cu")
		(net "GND")
	)
	(via
		(at 90.604594 -280.778204)
		(size 0.4572)
		(drill 0.2032)
		(layers "F.Cu" "B.Cu")
		(net "GND")
	)
	(via
		(at 59.842146 -270.416782)
		(size 0.4572)
		(drill 0.2032)
		(layers "F.Cu" "B.Cu")
		(net "GND")
	)
	(via
		(at 137.594594 -272.639282)
		(size 0.4318)
		(drill 0.2032)
		(layers "F.Cu" "B.Cu")
		(net "GND")
	)
	(via
		(at 453.435212 -22.841458)
		(size 0.508)
		(drill 0.254)
		(layers "F.Cu" "B.Cu")
		(net "GND")
	)
	(via
		(at 49.666906 -10.16508)
		(size 0.508)
		(drill 0.254)
		(layers "F.Cu" "B.Cu")
		(net "GND")
	)
	(via
		(at 428.279814 -290.816792)
		(size 0.4572)
		(drill 0.2032)
		(layers "F.Cu" "B.Cu")
		(net "GND")
	)
	(via
		(at 344.183462 -262.872474)
		(size 0.4572)
		(drill 0.2032)
		(layers "F.Cu" "B.Cu")
		(net "GND")
	)
	(via
		(at 442.133482 -200.716642)
		(size 0.4572)
		(drill 0.2032)
		(layers "F.Cu" "B.Cu")
		(net "GND")
	)
	(via
		(at 400.526504 -6.07949)
		(size 0.508)
		(drill 0.254)
		(layers "F.Cu" "B.Cu")
		(net "GND")
	)
	(via
		(at 170.555666 -109.375448)
		(size 0.4572)
		(drill 0.254)
		(layers "F.Cu" "B.Cu")
		(net "GND")
	)
	(via
		(at 287.284668 -364.759494)
		(size 0.49022)
		(drill 0.254)
		(layers "F.Cu" "B.Cu")
		(net "GND")
	)
	(via
		(at 415.402014 -221.96679)
		(size 0.4572)
		(drill 0.2032)
		(layers "F.Cu" "B.Cu")
		(net "GND")
	)
	(via
		(at 375.447306 -175.232568)
		(size 0.508)
		(drill 0.254)
		(layers "F.Cu" "B.Cu")
		(net "GND")
	)
	(via
		(at 380.725934 -220.319854)
		(size 0.4572)
		(drill 0.2032)
		(layers "F.Cu" "B.Cu")
		(net "GND")
	)
	(via
		(at 345.593162 -283.219906)
		(size 0.4572)
		(drill 0.2032)
		(layers "F.Cu" "B.Cu")
		(net "GND")
	)
	(via
		(at 26.223214 -221.116652)
		(size 0.4572)
		(drill 0.2032)
		(layers "F.Cu" "B.Cu")
		(net "GND")
	)
	(via
		(at 417.072572 -210.066636)
		(size 0.4572)
		(drill 0.2032)
		(layers "F.Cu" "B.Cu")
		(net "GND")
	)
	(via
		(at 406.267158 -406.370536)
		(size 0.4572)
		(drill 0.254)
		(layers "F.Cu" "B.Cu")
		(net "GND")
	)
	(via
		(at 41.584372 -353.187)
		(size 0.49022)
		(drill 0.254)
		(layers "F.Cu" "B.Cu")
		(net "GND")
	)
	(via
		(at 137.888218 -360.74223)
		(size 0.6604)
		(drill 0.3302)
		(layers "F.Cu" "B.Cu")
		(net "GND")
	)
	(via
		(at 53.45049 -410.664152)
		(size 0.4572)
		(drill 0.254)
		(layers "F.Cu" "B.Cu")
		(net "GND")
	)
	(via
		(at 249.28703 -45.988732)
		(size 0.508)
		(drill 0.254)
		(layers "F.Cu" "B.Cu")
		(net "GND")
	)
	(via
		(at 179.105814 -277.216616)
		(size 0.4572)
		(drill 0.2032)
		(layers "F.Cu" "B.Cu")
		(net "GND")
	)
	(via
		(at 216.824814 -305.266598)
		(size 0.4572)
		(drill 0.2032)
		(layers "F.Cu" "B.Cu")
		(net "GND")
	)
	(via
		(at 91.675458 -192.44691)
		(size 0.508)
		(drill 0.254)
		(layers "F.Cu" "B.Cu")
		(net "GND")
	)
	(via
		(at 259.075682 -299.316648)
		(size 0.4572)
		(drill 0.2032)
		(layers "F.Cu" "B.Cu")
		(net "GND")
	)
	(via
		(at 28.433014 -215.166702)
		(size 0.4572)
		(drill 0.2032)
		(layers "F.Cu" "B.Cu")
		(net "GND")
	)
	(via
		(at 334.675734 -241.481102)
		(size 0.4318)
		(drill 0.2032)
		(layers "F.Cu" "B.Cu")
		(net "GND")
	)
	(via
		(at 296.794682 -241.516662)
		(size 0.4572)
		(drill 0.2032)
		(layers "F.Cu" "B.Cu")
		(net "GND")
	)
	(via
		(at 118.798594 -274.266914)
		(size 0.4572)
		(drill 0.2032)
		(layers "F.Cu" "B.Cu")
		(net "GND")
	)
	(via
		(at 23.210266 -19.13636)
		(size 0.508)
		(drill 0.254)
		(layers "F.Cu" "B.Cu")
		(net "GND")
	)
	(via
		(at 292.694614 -313.766708)
		(size 0.4572)
		(drill 0.2032)
		(layers "F.Cu" "B.Cu")
		(net "GND")
	)
	(via
		(at 334.25003 -438.499758)
		(size 0.4572)
		(drill 0.2032)
		(layers "F.Cu" "B.Cu")
		(net "GND")
	)
	(via
		(at 342.735154 -56.438292)
		(size 0.4572)
		(drill 0.2032)
		(layers "F.Cu" "B.Cu")
		(net "GND")
	)
	(via
		(at 334.785462 -256.361438)
		(size 0.4318)
		(drill 0.2032)
		(layers "F.Cu" "B.Cu")
		(net "GND")
	)
	(via
		(at 367.678462 -266.128246)
		(size 0.4572)
		(drill 0.2032)
		(layers "F.Cu" "B.Cu")
		(net "GND")
	)
	(via
		(at 21.83384 -56.999886)
		(size 0.508)
		(drill 0.254)
		(layers "F.Cu" "B.Cu")
		(net "GND")
	)
	(via
		(at 383.655062 -269.38351)
		(size 0.4572)
		(drill 0.2032)
		(layers "F.Cu" "B.Cu")
		(net "GND")
	)
	(via
		(at 190.093346 -270.416782)
		(size 0.4572)
		(drill 0.2032)
		(layers "F.Cu" "B.Cu")
		(net "GND")
	)
	(via
		(at 380.31801 -407.00452)
		(size 0.4064)
		(drill 0.2032)
		(layers "F.Cu" "B.Cu")
		(net "GND")
	)
	(via
		(at 151.848566 -401.492212)
		(size 0.4572)
		(drill 0.254)
		(layers "F.Cu" "B.Cu")
		(net "GND")
	)
	(via
		(at 207.02016 -150.056088)
		(size 0.508)
		(drill 0.254)
		(layers "F.Cu" "B.Cu")
		(net "GND")
	)
	(via
		(at 348.465648 -329.76312)
		(size 0.508)
		(drill 0.254)
		(layers "F.Cu" "B.Cu")
		(net "GND")
	)
	(via
		(at 336.085434 -221.133924)
		(size 0.4572)
		(drill 0.2032)
		(layers "F.Cu" "B.Cu")
		(net "GND")
	)
	(via
		(at 419.502082 -262.76681)
		(size 0.4572)
		(drill 0.2032)
		(layers "F.Cu" "B.Cu")
		(net "GND")
	)
	(via
		(at 51.064414 -282.316682)
		(size 0.4572)
		(drill 0.2032)
		(layers "F.Cu" "B.Cu")
		(net "GND")
	)
	(via
		(at 332.144624 -339.624416)
		(size 0.508)
		(drill 0.254)
		(layers "F.Cu" "B.Cu")
		(net "GND")
	)
	(via
		(at 339.954362 -283.219906)
		(size 0.4572)
		(drill 0.2032)
		(layers "F.Cu" "B.Cu")
		(net "GND")
	)
	(via
		(at 414.85947 -180.149754)
		(size 0.49022)
		(drill 0.254)
		(layers "F.Cu" "B.Cu")
		(net "GND")
	)
	(via
		(at 50.428906 -18.246344)
		(size 0.508)
		(drill 0.254)
		(layers "F.Cu" "B.Cu")
		(net "GND")
	)
	(via
		(at 205.180946 -283.166566)
		(size 0.4572)
		(drill 0.2032)
		(layers "F.Cu" "B.Cu")
		(net "GND")
	)
	(via
		(at 405.648414 -304.416714)
		(size 0.4572)
		(drill 0.2032)
		(layers "F.Cu" "B.Cu")
		(net "GND")
	)
	(via
		(at 337.107784 -342.663272)
		(size 0.508)
		(drill 0.254)
		(layers "F.Cu" "B.Cu")
		(net "GND")
	)
	(via
		(at 234.860338 -135.570976)
		(size 0.508)
		(drill 0.254)
		(layers "F.Cu" "B.Cu")
		(net "GND")
	)
	(via
		(at 415.402014 -248.31675)
		(size 0.4572)
		(drill 0.2032)
		(layers "F.Cu" "B.Cu")
		(net "GND")
	)
	(via
		(at 18.679414 -216.866724)
		(size 0.4572)
		(drill 0.2032)
		(layers "F.Cu" "B.Cu")
		(net "GND")
	)
	(via
		(at 143.637 -36.894008)
		(size 0.508)
		(drill 0.254)
		(layers "F.Cu" "B.Cu")
		(net "GND")
	)
	(via
		(at 52.298346 -279.766776)
		(size 0.4572)
		(drill 0.2032)
		(layers "F.Cu" "B.Cu")
		(net "GND")
	)
	(via
		(at 257.185414 -276.366732)
		(size 0.4572)
		(drill 0.2032)
		(layers "F.Cu" "B.Cu")
		(net "GND")
	)
	(via
		(at 370.498116 -256.361438)
		(size 0.4572)
		(drill 0.2032)
		(layers "F.Cu" "B.Cu")
		(net "GND")
	)
	(via
		(at 412.161482 -272.966688)
		(size 0.4572)
		(drill 0.2032)
		(layers "F.Cu" "B.Cu")
		(net "GND")
	)
	(via
		(at 106.111294 -276.708616)
		(size 0.4572)
		(drill 0.2032)
		(layers "F.Cu" "B.Cu")
		(net "GND")
	)
	(via
		(at 230.80345 -115.668044)
		(size 0.508)
		(drill 0.254)
		(layers "F.Cu" "B.Cu")
		(net "GND")
	)
	(via
		(at 413.192214 -268.71676)
		(size 0.4572)
		(drill 0.2032)
		(layers "F.Cu" "B.Cu")
		(net "GND")
	)
	(via
		(at 434.589682 -194.766692)
		(size 0.4572)
		(drill 0.2032)
		(layers "F.Cu" "B.Cu")
		(net "GND")
	)
	(via
		(at 343.13368 -239.853216)
		(size 0.4572)
		(drill 0.2032)
		(layers "F.Cu" "B.Cu")
		(net "GND")
	)
	(via
		(at 307.782214 -272.116804)
		(size 0.4572)
		(drill 0.2032)
		(layers "F.Cu" "B.Cu")
		(net "GND")
	)
	(via
		(at 180.339746 -260.21665)
		(size 0.4572)
		(drill 0.2032)
		(layers "F.Cu" "B.Cu")
		(net "GND")
	)
	(via
		(at 147.349972 -438.651396)
		(size 0.4572)
		(drill 0.2032)
		(layers "F.Cu" "B.Cu")
		(net "GND")
	)
	(via
		(at 415.643822 -46.171612)
		(size 0.508)
		(drill 0.254)
		(layers "F.Cu" "B.Cu")
		(net "GND")
	)
	(via
		(at 337.025234 -222.761556)
		(size 0.4572)
		(drill 0.2032)
		(layers "F.Cu" "B.Cu")
		(net "GND")
	)
	(via
		(at 438.033414 -263.616694)
		(size 0.4572)
		(drill 0.2032)
		(layers "F.Cu" "B.Cu")
		(net "GND")
	)
	(via
		(at 377.546616 -257.175254)
		(size 0.4572)
		(drill 0.2032)
		(layers "F.Cu" "B.Cu")
		(net "GND")
	)
	(via
		(at 294.904414 -225.36658)
		(size 0.4572)
		(drill 0.2032)
		(layers "F.Cu" "B.Cu")
		(net "GND")
	)
	(via
		(at 307.782214 -260.21665)
		(size 0.4572)
		(drill 0.2032)
		(layers "F.Cu" "B.Cu")
		(net "GND")
	)
	(via
		(at 277.607014 -300.166786)
		(size 0.4572)
		(drill 0.2032)
		(layers "F.Cu" "B.Cu")
		(net "GND")
	)
	(via
		(at 460.664814 -242.3668)
		(size 0.4572)
		(drill 0.2032)
		(layers "F.Cu" "B.Cu")
		(net "GND")
	)
	(via
		(at 464.764882 -222.816674)
		(size 0.4572)
		(drill 0.2032)
		(layers "F.Cu" "B.Cu")
		(net "GND")
	)
	(via
		(at 210.514946 -273.816572)
		(size 0.4572)
		(drill 0.2032)
		(layers "F.Cu" "B.Cu")
		(net "GND")
	)
	(via
		(at 109.400594 -272.639282)
		(size 0.4572)
		(drill 0.2032)
		(layers "F.Cu" "B.Cu")
		(net "GND")
	)
	(via
		(at 373.317516 -272.639282)
		(size 0.4572)
		(drill 0.2032)
		(layers "F.Cu" "B.Cu")
		(net "GND")
	)
	(via
		(at 325.250048 -430.147222)
		(size 0.4572)
		(drill 0.2032)
		(layers "F.Cu" "B.Cu")
		(net "GND")
	)
	(via
		(at 348.549722 -183.161432)
		(size 0.508)
		(drill 0.254)
		(layers "F.Cu" "B.Cu")
		(net "GND")
	)
	(via
		(at 119.268748 -286.475424)
		(size 0.4572)
		(drill 0.2032)
		(layers "F.Cu" "B.Cu")
		(net "GND")
	)
	(via
		(at 14.579346 -287.416748)
		(size 0.4572)
		(drill 0.2032)
		(layers "F.Cu" "B.Cu")
		(net "GND")
	)
	(via
		(at 337.965034 -216.25052)
		(size 0.4572)
		(drill 0.2032)
		(layers "F.Cu" "B.Cu")
		(net "GND")
	)
	(via
		(at 157.708346 -289.11677)
		(size 0.4572)
		(drill 0.2032)
		(layers "F.Cu" "B.Cu")
		(net "GND")
	)
	(via
		(at 417.082732 -219.41663)
		(size 0.4572)
		(drill 0.2032)
		(layers "F.Cu" "B.Cu")
		(net "GND")
	)
	(via
		(at 31.751778 -100.602034)
		(size 0.508)
		(drill 0.254)
		(layers "F.Cu" "B.Cu")
		(net "GND")
	)
	(via
		(at 449.71208 -92.493592)
		(size 0.508)
		(drill 0.254)
		(layers "F.Cu" "B.Cu")
		(net "GND")
	)
	(via
		(at 343.243408 -253.10592)
		(size 0.4572)
		(drill 0.2032)
		(layers "F.Cu" "B.Cu")
		(net "GND")
	)
	(via
		(at 365.689134 -223.575626)
		(size 0.4572)
		(drill 0.2032)
		(layers "F.Cu" "B.Cu")
		(net "GND")
	)
	(via
		(at 201.737214 -261.066788)
		(size 0.4572)
		(drill 0.2032)
		(layers "F.Cu" "B.Cu")
		(net "GND")
	)
	(via
		(at 458.81671 -39.124128)
		(size 0.508)
		(drill 0.254)
		(layers "F.Cu" "B.Cu")
		(net "GND")
	)
	(via
		(at 157.708346 -234.716574)
		(size 0.4572)
		(drill 0.2032)
		(layers "F.Cu" "B.Cu")
		(net "GND")
	)
	(via
		(at 156.716222 -400.224244)
		(size 0.4572)
		(drill 0.254)
		(layers "F.Cu" "B.Cu")
		(net "GND")
	)
	(via
		(at 436.155846 -382.49733)
		(size 0.508)
		(drill 0.254)
		(layers "F.Cu" "B.Cu")
		(net "GND")
	)
	(via
		(at 361.569762 -268.569694)
		(size 0.4572)
		(drill 0.2032)
		(layers "F.Cu" "B.Cu")
		(net "GND")
	)
	(via
		(at 102.821994 -274.266914)
		(size 0.4572)
		(drill 0.2032)
		(layers "F.Cu" "B.Cu")
		(net "GND")
	)
	(via
		(at 307.782214 -244.916706)
		(size 0.4572)
		(drill 0.2032)
		(layers "F.Cu" "B.Cu")
		(net "GND")
	)
	(via
		(at 407.858214 -212.616796)
		(size 0.4572)
		(drill 0.2032)
		(layers "F.Cu" "B.Cu")
		(net "GND")
	)
	(via
		(at 143.725646 -342.129872)
		(size 0.508)
		(drill 0.254)
		(layers "F.Cu" "B.Cu")
		(net "GND")
	)
	(via
		(at 142.385034 -407.00452)
		(size 0.4064)
		(drill 0.2032)
		(layers "F.Cu" "B.Cu")
		(net "GND")
	)
	(via
		(at 265.10488 -149.697948)
		(size 0.508)
		(drill 0.254)
		(layers "F.Cu" "B.Cu")
		(net "GND")
	)
	(via
		(at 315.250068 -431.451258)
		(size 0.4572)
		(drill 0.2032)
		(layers "F.Cu" "B.Cu")
		(net "GND")
	)
	(via
		(at 29.666946 -276.366732)
		(size 0.4572)
		(drill 0.2032)
		(layers "F.Cu" "B.Cu")
		(net "GND")
	)
	(via
		(at 340.894416 -255.547622)
		(size 0.4572)
		(drill 0.2032)
		(layers "F.Cu" "B.Cu")
		(net "GND")
	)
	(via
		(at 214.615014 -272.966688)
		(size 0.4572)
		(drill 0.2032)
		(layers "F.Cu" "B.Cu")
		(net "GND")
	)
	(via
		(at 180.339746 -307.816758)
		(size 0.4572)
		(drill 0.2032)
		(layers "F.Cu" "B.Cu")
		(net "GND")
	)
	(via
		(at 162.481514 -400.858228)
		(size 0.4064)
		(drill 0.2032)
		(layers "F.Cu" "B.Cu")
		(net "GND")
	)
	(via
		(at 172.955712 -118.975378)
		(size 0.4572)
		(drill 0.254)
		(layers "F.Cu" "B.Cu")
		(net "GND")
	)
	(via
		(at 274.163282 -258.516628)
		(size 0.4572)
		(drill 0.2032)
		(layers "F.Cu" "B.Cu")
		(net "GND")
	)
	(via
		(at 439.923682 -238.116618)
		(size 0.4572)
		(drill 0.2032)
		(layers "F.Cu" "B.Cu")
		(net "GND")
	)
	(via
		(at 307.566314 -287.416748)
		(size 0.4572)
		(drill 0.2032)
		(layers "F.Cu" "B.Cu")
		(net "GND")
	)
	(via
		(at 157.708346 -197.316598)
		(size 0.4572)
		(drill 0.2032)
		(layers "F.Cu" "B.Cu")
		(net "GND")
	)
	(via
		(at 97.543366 -248.806208)
		(size 0.4572)
		(drill 0.2032)
		(layers "F.Cu" "B.Cu")
		(net "GND")
	)
	(via
		(at 411.958282 -266.1666)
		(size 0.4572)
		(drill 0.2032)
		(layers "F.Cu" "B.Cu")
		(net "GND")
	)
	(via
		(at 184.439814 -308.666642)
		(size 0.4572)
		(drill 0.2032)
		(layers "F.Cu" "B.Cu")
		(net "GND")
	)
	(via
		(at 373.207534 -213.732618)
		(size 0.4572)
		(drill 0.2032)
		(layers "F.Cu" "B.Cu")
		(net "GND")
	)
	(via
		(at 352.3361 -407.638504)
		(size 0.4572)
		(drill 0.254)
		(layers "F.Cu" "B.Cu")
		(net "GND")
	)
	(via
		(at 193.893186 -439.29808)
		(size 0.508)
		(drill 0.254)
		(layers "F.Cu" "B.Cu")
		(net "GND")
	)
	(via
		(at 455.011282 -286.56661)
		(size 0.4572)
		(drill 0.2032)
		(layers "F.Cu" "B.Cu")
		(net "GND")
	)
	(via
		(at 380.415038 -401.492212)
		(size 0.4572)
		(drill 0.254)
		(layers "F.Cu" "B.Cu")
		(net "GND")
	)
	(via
		(at 345.722194 -60.057792)
		(size 0.49022)
		(drill 0.254)
		(layers "F.Cu" "B.Cu")
		(net "GND")
	)
	(via
		(at 177.561748 -352.074988)
		(size 0.508)
		(drill 0.254)
		(layers "F.Cu" "B.Cu")
		(net "GND")
	)
	(via
		(at 132.315712 -240.667286)
		(size 0.4572)
		(drill 0.2032)
		(layers "F.Cu" "B.Cu")
		(net "GND")
	)
	(via
		(at 445.577214 -298.466764)
		(size 0.4572)
		(drill 0.2032)
		(layers "F.Cu" "B.Cu")
		(net "GND")
	)
	(via
		(at 329.54722 -400.224244)
		(size 0.4572)
		(drill 0.254)
		(layers "F.Cu" "B.Cu")
		(net "GND")
	)
	(via
		(at 207.071214 -204.116686)
		(size 0.4572)
		(drill 0.2032)
		(layers "F.Cu" "B.Cu")
		(net "GND")
	)
	(via
		(at 104.701594 -285.661354)
		(size 0.4572)
		(drill 0.2032)
		(layers "F.Cu" "B.Cu")
		(net "GND")
	)
	(via
		(at 302.664114 -313.766708)
		(size 0.4572)
		(drill 0.2032)
		(layers "F.Cu" "B.Cu")
		(net "GND")
	)
	(via
		(at 90.964512 -230.900478)
		(size 0.4572)
		(drill 0.2032)
		(layers "F.Cu" "B.Cu")
		(net "GND")
	)
	(via
		(at 178.266852 -11.458448)
		(size 0.508)
		(drill 0.254)
		(layers "F.Cu" "B.Cu")
		(net "GND")
	)
	(via
		(at 80.696054 -342.556084)
		(size 0.49022)
		(drill 0.254)
		(layers "F.Cu" "B.Cu")
		(net "GND")
	)
	(via
		(at 147.938744 -91.702128)
		(size 0.508)
		(drill 0.254)
		(layers "F.Cu" "B.Cu")
		(net "GND")
	)
	(via
		(at 99.062794 -280.778204)
		(size 0.4572)
		(drill 0.2032)
		(layers "F.Cu" "B.Cu")
		(net "GND")
	)
	(via
		(at 176.896014 -297.616626)
		(size 0.4572)
		(drill 0.2032)
		(layers "F.Cu" "B.Cu")
		(net "GND")
	)
	(via
		(at 91.074748 -253.919736)
		(size 0.4572)
		(drill 0.2032)
		(layers "F.Cu" "B.Cu")
		(net "GND")
	)
	(via
		(at 67.250056 -433.899564)
		(size 0.4572)
		(drill 0.2032)
		(layers "F.Cu" "B.Cu")
		(net "GND")
	)
	(via
		(at 333.845408 -253.10592)
		(size 0.4572)
		(drill 0.2032)
		(layers "F.Cu" "B.Cu")
		(net "GND")
	)
	(via
		(at 411.958282 -230.466646)
		(size 0.4572)
		(drill 0.2032)
		(layers "F.Cu" "B.Cu")
		(net "GND")
	)
	(via
		(at 86.265766 -224.389442)
		(size 0.4572)
		(drill 0.2032)
		(layers "F.Cu" "B.Cu")
		(net "GND")
	)
	(via
		(at 93.784166 -242.294918)
		(size 0.4572)
		(drill 0.2032)
		(layers "F.Cu" "B.Cu")
		(net "GND")
	)
	(via
		(at 58.608214 -299.316648)
		(size 0.4572)
		(drill 0.2032)
		(layers "F.Cu" "B.Cu")
		(net "GND")
	)
	(via
		(at 179.105814 -306.96662)
		(size 0.4572)
		(drill 0.2032)
		(layers "F.Cu" "B.Cu")
		(net "GND")
	)
	(via
		(at 337.49488 -244.73662)
		(size 0.4572)
		(drill 0.2032)
		(layers "F.Cu" "B.Cu")
		(net "GND")
	)
	(via
		(at 199.527414 -275.516594)
		(size 0.4572)
		(drill 0.2032)
		(layers "F.Cu" "B.Cu")
		(net "GND")
	)
	(via
		(at 382.147572 -339.339428)
		(size 0.508)
		(drill 0.254)
		(layers "F.Cu" "B.Cu")
		(net "GND")
	)
	(via
		(at 172.795946 -313.766708)
		(size 0.4572)
		(drill 0.2032)
		(layers "F.Cu" "B.Cu")
		(net "GND")
	)
	(via
		(at 37.210746 -246.616728)
		(size 0.4572)
		(drill 0.2032)
		(layers "F.Cu" "B.Cu")
		(net "GND")
	)
	(via
		(at 295.077896 -360.833924)
		(size 0.508)
		(drill 0.254)
		(layers "F.Cu" "B.Cu")
		(net "GND")
	)
	(via
		(at 294.904414 -307.816758)
		(size 0.4572)
		(drill 0.2032)
		(layers "F.Cu" "B.Cu")
		(net "GND")
	)
	(via
		(at 46.964346 -317.166752)
		(size 0.4572)
		(drill 0.2032)
		(layers "F.Cu" "B.Cu")
		(net "GND")
	)
	(via
		(at 48.854614 -280.61666)
		(size 0.4572)
		(drill 0.2032)
		(layers "F.Cu" "B.Cu")
		(net "GND")
	)
	(via
		(at 37.210746 -195.616576)
		(size 0.4572)
		(drill 0.2032)
		(layers "F.Cu" "B.Cu")
		(net "GND")
	)
	(via
		(at 24.447754 -400.693128)
		(size 0.508)
		(drill 0.254)
		(layers "F.Cu" "B.Cu")
		(net "GND")
	)
	(via
		(at 92.459556 -97.105216)
		(size 0.508)
		(drill 0.254)
		(layers "F.Cu" "B.Cu")
		(net "GND")
	)
	(via
		(at 195.427346 -315.46673)
		(size 0.4572)
		(drill 0.2032)
		(layers "F.Cu" "B.Cu")
		(net "GND")
	)
	(via
		(at 314.307982 -216.866724)
		(size 0.4572)
		(drill 0.2032)
		(layers "F.Cu" "B.Cu")
		(net "GND")
	)
	(via
		(at 285.150814 -206.666592)
		(size 0.4572)
		(drill 0.2032)
		(layers "F.Cu" "B.Cu")
		(net "GND")
	)
	(via
		(at 389.97128 -28.717748)
		(size 0.508)
		(drill 0.254)
		(layers "F.Cu" "B.Cu")
		(net "GND")
	)
	(via
		(at 7.035546 -258.516628)
		(size 0.4572)
		(drill 0.2032)
		(layers "F.Cu" "B.Cu")
		(net "GND")
	)
	(via
		(at 66.152014 -291.666676)
		(size 0.4572)
		(drill 0.2032)
		(layers "F.Cu" "B.Cu")
		(net "GND")
	)
	(via
		(at 380.835662 -275.8948)
		(size 0.4572)
		(drill 0.2032)
		(layers "F.Cu" "B.Cu")
		(net "GND")
	)
	(via
		(at 104.121966 -222.761556)
		(size 0.4572)
		(drill 0.2032)
		(layers "F.Cu" "B.Cu")
		(net "GND")
	)
	(via
		(at 372.571518 -407.638504)
		(size 0.4572)
		(drill 0.254)
		(layers "F.Cu" "B.Cu")
		(net "GND")
	)
	(via
		(at 291.460682 -312.91657)
		(size 0.4572)
		(drill 0.2032)
		(layers "F.Cu" "B.Cu")
		(net "GND")
	)
	(via
		(at 184.439814 -241.516662)
		(size 0.4572)
		(drill 0.2032)
		(layers "F.Cu" "B.Cu")
		(net "GND")
	)
	(via
		(at 134.305548 -263.686544)
		(size 0.4572)
		(drill 0.2032)
		(layers "F.Cu" "B.Cu")
		(net "GND")
	)
	(via
		(at 200.976484 -323.434456)
		(size 0.4572)
		(drill 0.2032)
		(layers "F.Cu" "B.Cu")
		(net "GND")
	)
	(via
		(at 369.44808 -239.853216)
		(size 0.4572)
		(drill 0.2032)
		(layers "F.Cu" "B.Cu")
		(net "GND")
	)
	(via
		(at 13.6652 -110.604554)
		(size 0.508)
		(drill 0.254)
		(layers "F.Cu" "B.Cu")
		(net "GND")
	)
	(via
		(at 434.589682 -299.316648)
		(size 0.4572)
		(drill 0.2032)
		(layers "F.Cu" "B.Cu")
		(net "GND")
	)
	(via
		(at 20.889214 -204.116686)
		(size 0.4572)
		(drill 0.2032)
		(layers "F.Cu" "B.Cu")
		(net "GND")
	)
	(via
		(at 358.280462 -254.733552)
		(size 0.4572)
		(drill 0.2032)
		(layers "F.Cu" "B.Cu")
		(net "GND")
	)
	(via
		(at 53.031136 -6.597396)
		(size 0.508)
		(drill 0.254)
		(layers "F.Cu" "B.Cu")
		(net "GND")
	)
	(via
		(at 115.342162 -237.149386)
		(size 0.4572)
		(drill 0.2032)
		(layers "F.Cu" "B.Cu")
		(net "GND")
	)
	(via
		(at 20.889214 -280.61666)
		(size 0.4572)
		(drill 0.2032)
		(layers "F.Cu" "B.Cu")
		(net "GND")
	)
	(via
		(at 340.784434 -242.294918)
		(size 0.4572)
		(drill 0.2032)
		(layers "F.Cu" "B.Cu")
		(net "GND")
	)
	(via
		(at 39.420546 -234.716574)
		(size 0.4572)
		(drill 0.2032)
		(layers "F.Cu" "B.Cu")
		(net "GND")
	)
	(via
		(at 462.555082 -286.56661)
		(size 0.4572)
		(drill 0.2032)
		(layers "F.Cu" "B.Cu")
		(net "GND")
	)
	(via
		(at 268.829282 -235.566712)
		(size 0.4572)
		(drill 0.2032)
		(layers "F.Cu" "B.Cu")
		(net "GND")
	)
	(via
		(at 136.294114 -344.90533)
		(size 0.49022)
		(drill 0.254)
		(layers "F.Cu" "B.Cu")
		(net "GND")
	)
	(via
		(at 32.06115 -131.157472)
		(size 0.508)
		(drill 0.254)
		(layers "F.Cu" "B.Cu")
		(net "GND")
	)
	(via
		(at 95.193612 -230.086662)
		(size 0.4572)
		(drill 0.2032)
		(layers "F.Cu" "B.Cu")
		(net "GND")
	)
	(via
		(at 160.212024 -227.066602)
		(size 0.4572)
		(drill 0.2032)
		(layers "F.Cu" "B.Cu")
		(net "GND")
	)
	(via
		(at 82.462878 -407.00452)
		(size 0.4064)
		(drill 0.2032)
		(layers "F.Cu" "B.Cu")
		(net "GND")
	)
	(via
		(at 216.824814 -282.316682)
		(size 0.4572)
		(drill 0.2032)
		(layers "F.Cu" "B.Cu")
		(net "GND")
	)
	(via
		(at 423.214292 -402.671534)
		(size 0.508)
		(drill 0.254)
		(layers "F.Cu" "B.Cu")
		(net "GND")
	)
	(via
		(at 55.703724 -177.987452)
		(size 0.508)
		(drill 0.254)
		(layers "F.Cu" "B.Cu")
		(net "GND")
	)
	(via
		(at 411.958282 -277.216616)
		(size 0.4572)
		(drill 0.2032)
		(layers "F.Cu" "B.Cu")
		(net "GND")
	)
	(via
		(at 363.0295 -412.341314)
		(size 0.508)
		(drill 0.254)
		(layers "F.Cu" "B.Cu")
		(net "GND")
	)
	(via
		(at 35.976814 -219.41663)
		(size 0.4572)
		(drill 0.2032)
		(layers "F.Cu" "B.Cu")
		(net "GND")
	)
	(via
		(at 277.607014 -295.06672)
		(size 0.4572)
		(drill 0.2032)
		(layers "F.Cu" "B.Cu")
		(net "GND")
	)
	(via
		(at 159.918146 -270.416782)
		(size 0.4572)
		(drill 0.2032)
		(layers "F.Cu" "B.Cu")
		(net "GND")
	)
	(via
		(at 66.244978 -107.798362)
		(size 0.508)
		(drill 0.254)
		(layers "F.Cu" "B.Cu")
		(net "GND")
	)
	(via
		(at 376.99061 -403.883876)
		(size 0.4064)
		(drill 0.2032)
		(layers "F.Cu" "B.Cu")
		(net "GND")
	)
	(via
		(at 428.279814 -292.516814)
		(size 0.4572)
		(drill 0.2032)
		(layers "F.Cu" "B.Cu")
		(net "GND")
	)
	(via
		(at 104.85628 -58.908188)
		(size 0.508)
		(drill 0.254)
		(layers "F.Cu" "B.Cu")
		(net "GND")
	)
	(via
		(at 183.53532 -12.492228)
		(size 0.508)
		(drill 0.254)
		(layers "F.Cu" "B.Cu")
		(net "GND")
	)
	(via
		(at 228.107748 -246.307864)
		(size 0.508)
		(drill 0.254)
		(layers "F.Cu" "B.Cu")
		(net "GND")
	)
	(via
		(at 214.615014 -228.766624)
		(size 0.4572)
		(drill 0.2032)
		(layers "F.Cu" "B.Cu")
		(net "GND")
	)
	(via
		(at 7.035546 -199.01662)
		(size 0.4572)
		(drill 0.2032)
		(layers "F.Cu" "B.Cu")
		(net "GND")
	)
	(via
		(at 420.736014 -195.616576)
		(size 0.4572)
		(drill 0.2032)
		(layers "F.Cu" "B.Cu")
		(net "GND")
	)
	(via
		(at 85.325712 -242.294918)
		(size 0.4572)
		(drill 0.2032)
		(layers "F.Cu" "B.Cu")
		(net "GND")
	)
	(via
		(at 458.455014 -214.316564)
		(size 0.4572)
		(drill 0.2032)
		(layers "F.Cu" "B.Cu")
		(net "GND")
	)
	(via
		(at 419.502082 -278.916638)
		(size 0.4572)
		(drill 0.2032)
		(layers "F.Cu" "B.Cu")
		(net "GND")
	)
	(via
		(at 371.797834 -219.506038)
		(size 0.4572)
		(drill 0.2032)
		(layers "F.Cu" "B.Cu")
		(net "GND")
	)
	(via
		(at 44.754546 -267.016738)
		(size 0.4572)
		(drill 0.2032)
		(layers "F.Cu" "B.Cu")
		(net "GND")
	)
	(via
		(at 348.772734 -223.575626)
		(size 0.4572)
		(drill 0.2032)
		(layers "F.Cu" "B.Cu")
		(net "GND")
	)
	(via
		(at 316.035436 -401.492212)
		(size 0.4572)
		(drill 0.254)
		(layers "F.Cu" "B.Cu")
		(net "GND")
	)
	(via
		(at 332.435962 -265.314176)
		(size 0.4572)
		(drill 0.2032)
		(layers "F.Cu" "B.Cu")
		(net "GND")
	)
	(via
		(at 95.193612 -244.73662)
		(size 0.4572)
		(drill 0.2032)
		(layers "F.Cu" "B.Cu")
		(net "GND")
	)
	(via
		(at 46.964346 -199.01662)
		(size 0.4572)
		(drill 0.2032)
		(layers "F.Cu" "B.Cu")
		(net "GND")
	)
	(via
		(at 214.615014 -288.266632)
		(size 0.4572)
		(drill 0.2032)
		(layers "F.Cu" "B.Cu")
		(net "GND")
	)
	(via
		(at 449.677282 -205.816708)
		(size 0.4572)
		(drill 0.2032)
		(layers "F.Cu" "B.Cu")
		(net "GND")
	)
	(via
		(at 288.470086 -354.868226)
		(size 0.508)
		(drill 0.254)
		(layers "F.Cu" "B.Cu")
		(net "GND")
	)
	(via
		(at 363.339634 -226.017328)
		(size 0.4572)
		(drill 0.2032)
		(layers "F.Cu" "B.Cu")
		(net "GND")
	)
	(via
		(at 38.695884 -323.434456)
		(size 0.4572)
		(drill 0.2032)
		(layers "F.Cu" "B.Cu")
		(net "GND")
	)
	(via
		(at 377.796044 -342.711532)
		(size 0.508)
		(drill 0.254)
		(layers "F.Cu" "B.Cu")
		(net "GND")
	)
	(via
		(at 45.868082 -19.13636)
		(size 0.508)
		(drill 0.254)
		(layers "F.Cu" "B.Cu")
		(net "GND")
	)
	(via
		(at 187.883546 -260.21665)
		(size 0.4572)
		(drill 0.2032)
		(layers "F.Cu" "B.Cu")
		(net "GND")
	)
	(via
		(at 435.823614 -203.266802)
		(size 0.4572)
		(drill 0.2032)
		(layers "F.Cu" "B.Cu")
		(net "GND")
	)
	(via
		(at 209.281014 -310.366664)
		(size 0.4572)
		(drill 0.2032)
		(layers "F.Cu" "B.Cu")
		(net "GND")
	)
	(via
		(at 389.843772 -16.967454)
		(size 0.508)
		(drill 0.254)
		(layers "F.Cu" "B.Cu")
		(net "GND")
	)
	(via
		(at 56.049672 -163.761674)
		(size 0.49022)
		(drill 0.254)
		(layers "F.Cu" "B.Cu")
		(net "GND")
	)
	(via
		(at 365.689134 -220.319854)
		(size 0.4572)
		(drill 0.2032)
		(layers "F.Cu" "B.Cu")
		(net "GND")
	)
	(via
		(at 177.612548 -359.14838)
		(size 0.508)
		(drill 0.254)
		(layers "F.Cu" "B.Cu")
		(net "GND")
	)
	(via
		(at 383.07518 -224.389442)
		(size 0.4572)
		(drill 0.2032)
		(layers "F.Cu" "B.Cu")
		(net "GND")
	)
	(via
		(at 80.937354 -5.821934)
		(size 0.508)
		(drill 0.254)
		(layers "F.Cu" "B.Cu")
		(net "GND")
	)
	(via
		(at 328.62647 -341.85225)
		(size 0.49022)
		(drill 0.254)
		(layers "F.Cu" "B.Cu")
		(net "GND")
	)
	(via
		(at 14.579346 -244.916706)
		(size 0.4572)
		(drill 0.2032)
		(layers "F.Cu" "B.Cu")
		(net "GND")
	)
	(via
		(at 26.223214 -232.166668)
		(size 0.4572)
		(drill 0.2032)
		(layers "F.Cu" "B.Cu")
		(net "GND")
	)
	(via
		(at 368.978434 -219.506038)
		(size 0.4572)
		(drill 0.2032)
		(layers "F.Cu" "B.Cu")
		(net "GND")
	)
	(via
		(at 375.836434 -358.879394)
		(size 0.508)
		(drill 0.254)
		(layers "F.Cu" "B.Cu")
		(net "GND")
	)
	(via
		(at 116.449348 -284.847538)
		(size 0.4572)
		(drill 0.2032)
		(layers "F.Cu" "B.Cu")
		(net "GND")
	)
	(via
		(at 121.447814 -331.776832)
		(size 0.49022)
		(drill 0.254)
		(layers "F.Cu" "B.Cu")
		(net "GND")
	)
	(via
		(at 205.180946 -227.066602)
		(size 0.4572)
		(drill 0.2032)
		(layers "F.Cu" "B.Cu")
		(net "GND")
	)
	(via
		(at 176.896014 -211.766658)
		(size 0.4572)
		(drill 0.2032)
		(layers "F.Cu" "B.Cu")
		(net "GND")
	)
	(via
		(at 460.664814 -306.116736)
		(size 0.4572)
		(drill 0.2032)
		(layers "F.Cu" "B.Cu")
		(net "GND")
	)
	(via
		(at 272.273014 -279.766776)
		(size 0.4572)
		(drill 0.2032)
		(layers "F.Cu" "B.Cu")
		(net "GND")
	)
	(via
		(at 332.326234 -239.0394)
		(size 0.4572)
		(drill 0.2032)
		(layers "F.Cu" "B.Cu")
		(net "GND")
	)
	(via
		(at 268.829282 -286.56661)
		(size 0.4572)
		(drill 0.2032)
		(layers "F.Cu" "B.Cu")
		(net "GND")
	)
	(via
		(at 374.288558 -401.492212)
		(size 0.4572)
		(drill 0.254)
		(layers "F.Cu" "B.Cu")
		(net "GND")
	)
	(via
		(at 199.527414 -202.416664)
		(size 0.4572)
		(drill 0.2032)
		(layers "F.Cu" "B.Cu")
		(net "GND")
	)
	(via
		(at 191.571626 -19.229578)
		(size 0.508)
		(drill 0.254)
		(layers "F.Cu" "B.Cu")
		(net "GND")
	)
	(via
		(at 409.748482 -200.716642)
		(size 0.4572)
		(drill 0.2032)
		(layers "F.Cu" "B.Cu")
		(net "GND")
	)
	(via
		(at 37.210746 -212.616796)
		(size 0.4572)
		(drill 0.2032)
		(layers "F.Cu" "B.Cu")
		(net "GND")
	)
	(via
		(at 338.544662 -279.150318)
		(size 0.4572)
		(drill 0.2032)
		(layers "F.Cu" "B.Cu")
		(net "GND")
	)
	(via
		(at 165.252146 -217.716608)
		(size 0.4572)
		(drill 0.2032)
		(layers "F.Cu" "B.Cu")
		(net "GND")
	)
	(via
		(at 157.708346 -240.666778)
		(size 0.4572)
		(drill 0.2032)
		(layers "F.Cu" "B.Cu")
		(net "GND")
	)
	(via
		(at 417.292282 -301.01667)
		(size 0.4572)
		(drill 0.2032)
		(layers "F.Cu" "B.Cu")
		(net "GND")
	)
	(via
		(at 11.135614 -235.566712)
		(size 0.4572)
		(drill 0.2032)
		(layers "F.Cu" "B.Cu")
		(net "GND")
	)
	(via
		(at 180.339746 -221.96679)
		(size 0.4572)
		(drill 0.2032)
		(layers "F.Cu" "B.Cu")
		(net "GND")
	)
	(via
		(at 56.398414 -241.516662)
		(size 0.4572)
		(drill 0.2032)
		(layers "F.Cu" "B.Cu")
		(net "GND")
	)
	(via
		(at 385.894834 -240.667286)
		(size 0.4318)
		(drill 0.2032)
		(layers "F.Cu" "B.Cu")
		(net "GND")
	)
	(via
		(at 400.092926 -77.197966)
		(size 0.508)
		(drill 0.254)
		(layers "F.Cu" "B.Cu")
		(net "GND")
	)
	(via
		(at 133.365494 -275.08073)
		(size 0.4572)
		(drill 0.2032)
		(layers "F.Cu" "B.Cu")
		(net "GND")
	)
	(via
		(at 13.345414 -235.566712)
		(size 0.4572)
		(drill 0.2032)
		(layers "F.Cu" "B.Cu")
		(net "GND")
	)
	(via
		(at 157.494732 -217.716608)
		(size 0.4572)
		(drill 0.2032)
		(layers "F.Cu" "B.Cu")
		(net "GND")
	)
	(via
		(at 356.373684 -249.00509)
		(size 0.4572)
		(drill 0.2032)
		(layers "F.Cu" "B.Cu")
		(net "GND")
	)
	(via
		(at 442.133482 -210.066636)
		(size 0.4572)
		(drill 0.2032)
		(layers "F.Cu" "B.Cu")
		(net "GND")
	)
	(via
		(at 380.835916 -254.733552)
		(size 0.4572)
		(drill 0.2032)
		(layers "F.Cu" "B.Cu")
		(net "GND")
	)
	(via
		(at 120.97893 -256.667)
		(size 0.4572)
		(drill 0.2032)
		(layers "F.Cu" "B.Cu")
		(net "GND")
	)
	(via
		(at 370.497862 -264.50036)
		(size 0.4572)
		(drill 0.2032)
		(layers "F.Cu" "B.Cu")
		(net "GND")
	)
	(via
		(at 175.355504 -114.975386)
		(size 0.4572)
		(drill 0.254)
		(layers "F.Cu" "B.Cu")
		(net "GND")
	)
	(via
		(at 111.640366 -216.25052)
		(size 0.4572)
		(drill 0.2032)
		(layers "F.Cu" "B.Cu")
		(net "GND")
	)
	(via
		(at 37.760402 -350.826578)
		(size 0.508)
		(drill 0.254)
		(layers "F.Cu" "B.Cu")
		(net "GND")
	)
	(via
		(at 128.4986 -79.136748)
		(size 0.508)
		(drill 0.254)
		(layers "F.Cu" "B.Cu")
		(net "GND")
	)
	(via
		(at 170.5229 -354.115878)
		(size 0.49022)
		(drill 0.254)
		(layers "F.Cu" "B.Cu")
		(net "GND")
	)
	(via
		(at 63.726314 -235.566712)
		(size 0.4572)
		(drill 0.2032)
		(layers "F.Cu" "B.Cu")
		(net "GND")
	)
	(via
		(at 111.966502 -332.56601)
		(size 0.49022)
		(drill 0.254)
		(layers "F.Cu" "B.Cu")
		(net "GND")
	)
	(via
		(at 311.882282 -221.116652)
		(size 0.4572)
		(drill 0.2032)
		(layers "F.Cu" "B.Cu")
		(net "GND")
	)
	(via
		(at 122.917966 -226.017328)
		(size 0.4572)
		(drill 0.2032)
		(layers "F.Cu" "B.Cu")
		(net "GND")
	)
	(via
		(at 257.185414 -238.966756)
		(size 0.4572)
		(drill 0.2032)
		(layers "F.Cu" "B.Cu")
		(net "GND")
	)
	(via
		(at 179.105814 -269.566644)
		(size 0.4572)
		(drill 0.2032)
		(layers "F.Cu" "B.Cu")
		(net "GND")
	)
	(via
		(at 113.629694 -286.475424)
		(size 0.4572)
		(drill 0.2032)
		(layers "F.Cu" "B.Cu")
		(net "GND")
	)
	(via
		(at 122.448066 -246.364506)
		(size 0.4572)
		(drill 0.2032)
		(layers "F.Cu" "B.Cu")
		(net "GND")
	)
	(via
		(at 349.917004 -67.288156)
		(size 0.508)
		(drill 0.254)
		(layers "F.Cu" "B.Cu")
		(net "GND")
	)
	(via
		(at 390.349994 -427.851316)
		(size 0.4572)
		(drill 0.2032)
		(layers "F.Cu" "B.Cu")
		(net "GND")
	)
	(via
		(at 449.677282 -284.866588)
		(size 0.4572)
		(drill 0.2032)
		(layers "F.Cu" "B.Cu")
		(net "GND")
	)
	(via
		(at 327.250044 -431.451258)
		(size 0.4572)
		(drill 0.2032)
		(layers "F.Cu" "B.Cu")
		(net "GND")
	)
	(via
		(at 302.664114 -236.416596)
		(size 0.4572)
		(drill 0.2032)
		(layers "F.Cu" "B.Cu")
		(net "GND")
	)
	(via
		(at 350.822006 -237.67923)
		(size 0.4572)
		(drill 0.2032)
		(layers "F.Cu" "B.Cu")
		(net "GND")
	)
	(via
		(at 35.976814 -233.86669)
		(size 0.4572)
		(drill 0.2032)
		(layers "F.Cu" "B.Cu")
		(net "GND")
	)
	(via
		(at 457.221082 -224.516696)
		(size 0.4572)
		(drill 0.2032)
		(layers "F.Cu" "B.Cu")
		(net "GND")
	)
	(via
		(at 110.700566 -226.017328)
		(size 0.4572)
		(drill 0.2032)
		(layers "F.Cu" "B.Cu")
		(net "GND")
	)
	(via
		(at 182.549546 -265.316716)
		(size 0.4572)
		(drill 0.2032)
		(layers "F.Cu" "B.Cu")
		(net "GND")
	)
	(via
		(at 197.637146 -263.616694)
		(size 0.4572)
		(drill 0.2032)
		(layers "F.Cu" "B.Cu")
		(net "GND")
	)
	(via
		(at 342.250014 -426.54728)
		(size 0.4572)
		(drill 0.2032)
		(layers "F.Cu" "B.Cu")
		(net "GND")
	)
	(via
		(at 9.245346 -238.966756)
		(size 0.4572)
		(drill 0.2032)
		(layers "F.Cu" "B.Cu")
		(net "GND")
	)
	(via
		(at 294.904414 -204.96657)
		(size 0.4572)
		(drill 0.2032)
		(layers "F.Cu" "B.Cu")
		(net "GND")
	)
	(via
		(at 342.250014 -437.34736)
		(size 0.4572)
		(drill 0.2032)
		(layers "F.Cu" "B.Cu")
		(net "GND")
	)
	(via
		(at 430.489614 -244.916706)
		(size 0.4572)
		(drill 0.2032)
		(layers "F.Cu" "B.Cu")
		(net "GND")
	)
	(via
		(at 262.266938 -62.973712)
		(size 0.6604)
		(drill 0.3302)
		(layers "F.Cu" "B.Cu")
		(net "GND")
	)
	(via
		(at 311.16778 -403.249892)
		(size 0.4572)
		(drill 0.254)
		(layers "F.Cu" "B.Cu")
		(net "GND")
	)
	(via
		(at 346.063062 -261.244842)
		(size 0.4572)
		(drill 0.2032)
		(layers "F.Cu" "B.Cu")
		(net "GND")
	)
	(via
		(at 65.151 -7.203948)
		(size 0.508)
		(drill 0.254)
		(layers "F.Cu" "B.Cu")
		(net "GND")
	)
	(via
		(at 54.508146 -279.766776)
		(size 0.4572)
		(drill 0.2032)
		(layers "F.Cu" "B.Cu")
		(net "GND")
	)
	(via
		(at 38.45687 -10.16508)
		(size 0.508)
		(drill 0.254)
		(layers "F.Cu" "B.Cu")
		(net "GND")
	)
	(via
		(at 274.163282 -215.166702)
		(size 0.4572)
		(drill 0.2032)
		(layers "F.Cu" "B.Cu")
		(net "GND")
	)
	(via
		(at 68.76669 -406.34666)
		(size 0.4572)
		(drill 0.254)
		(layers "F.Cu" "B.Cu")
		(net "GND")
	)
	(via
		(at 405.648414 -201.56678)
		(size 0.4572)
		(drill 0.2032)
		(layers "F.Cu" "B.Cu")
		(net "GND")
	)
	(via
		(at 411.958282 -294.216582)
		(size 0.4572)
		(drill 0.2032)
		(layers "F.Cu" "B.Cu")
		(net "GND")
	)
	(via
		(at 184.439814 -272.966688)
		(size 0.4572)
		(drill 0.2032)
		(layers "F.Cu" "B.Cu")
		(net "GND")
	)
	(via
		(at 332.796134 -223.575626)
		(size 0.4572)
		(drill 0.2032)
		(layers "F.Cu" "B.Cu")
		(net "GND")
	)
	(via
		(at 161.808414 -303.566576)
		(size 0.4572)
		(drill 0.2032)
		(layers "F.Cu" "B.Cu")
		(net "GND")
	)
	(via
		(at 134.14883 -103.81107)
		(size 0.508)
		(drill 0.254)
		(layers "F.Cu" "B.Cu")
		(net "GND")
	)
	(via
		(at 442.133482 -222.816674)
		(size 0.4572)
		(drill 0.2032)
		(layers "F.Cu" "B.Cu")
		(net "GND")
	)
	(via
		(at 455.011282 -239.81664)
		(size 0.4572)
		(drill 0.2032)
		(layers "F.Cu" "B.Cu")
		(net "GND")
	)
	(via
		(at 358.419654 -46.802802)
		(size 0.508)
		(drill 0.254)
		(layers "F.Cu" "B.Cu")
		(net "GND")
	)
	(via
		(at 452.628 -32.62757)
		(size 0.508)
		(drill 0.254)
		(layers "F.Cu" "B.Cu")
		(net "GND")
	)
	(via
		(at 307.782214 -250.016772)
		(size 0.4572)
		(drill 0.2032)
		(layers "F.Cu" "B.Cu")
		(net "GND")
	)
	(via
		(at 169.352214 -247.466612)
		(size 0.4572)
		(drill 0.2032)
		(layers "F.Cu" "B.Cu")
		(net "GND")
	)
	(via
		(at 45.657008 -7.215124)
		(size 0.508)
		(drill 0.254)
		(layers "F.Cu" "B.Cu")
		(net "GND")
	)
	(via
		(at 446.945766 -74.971656)
		(size 0.508)
		(drill 0.254)
		(layers "F.Cu" "B.Cu")
		(net "GND")
	)
	(via
		(at 367.678716 -288.917126)
		(size 0.4572)
		(drill 0.2032)
		(layers "F.Cu" "B.Cu")
		(net "GND")
	)
	(via
		(at 438.033414 -313.766708)
		(size 0.4572)
		(drill 0.2032)
		(layers "F.Cu" "B.Cu")
		(net "GND")
	)
	(via
		(at 133.255512 -232.528364)
		(size 0.4572)
		(drill 0.2032)
		(layers "F.Cu" "B.Cu")
		(net "GND")
	)
	(via
		(at 16.789146 -236.416596)
		(size 0.4572)
		(drill 0.2032)
		(layers "F.Cu" "B.Cu")
		(net "GND")
	)
	(via
		(at 346.893134 -213.732618)
		(size 0.4572)
		(drill 0.2032)
		(layers "F.Cu" "B.Cu")
		(net "GND")
	)
	(via
		(at 410.589222 -410.664152)
		(size 0.4572)
		(drill 0.254)
		(layers "F.Cu" "B.Cu")
		(net "GND")
	)
	(via
		(at 305.773328 -358.082088)
		(size 0.6604)
		(drill 0.3302)
		(layers "F.Cu" "B.Cu")
		(net "GND")
	)
	(via
		(at 370.51488 -45.176948)
		(size 0.508)
		(drill 0.254)
		(layers "F.Cu" "B.Cu")
		(net "GND")
	)
	(via
		(at 176.896014 -284.866588)
		(size 0.4572)
		(drill 0.2032)
		(layers "F.Cu" "B.Cu")
		(net "GND")
	)
	(via
		(at 58.608214 -297.616626)
		(size 0.4572)
		(drill 0.2032)
		(layers "F.Cu" "B.Cu")
		(net "GND")
	)
	(via
		(at 254.975614 -270.416782)
		(size 0.4572)
		(drill 0.2032)
		(layers "F.Cu" "B.Cu")
		(net "GND")
	)
	(via
		(at 357.717344 -330.382626)
		(size 0.508)
		(drill 0.254)
		(layers "F.Cu" "B.Cu")
		(net "GND")
	)
	(via
		(at 330.84008 -342.585548)
		(size 0.49022)
		(drill 0.254)
		(layers "F.Cu" "B.Cu")
		(net "GND")
	)
	(via
		(at 444.973964 -441.225432)
		(size 0.508)
		(drill 0.254)
		(layers "F.Cu" "B.Cu")
		(net "GND")
	)
	(via
		(at 296.720768 -407.44902)
		(size 0.508)
		(drill 0.254)
		(layers "F.Cu" "B.Cu")
		(net "GND")
	)
	(via
		(at 266.619482 -238.116618)
		(size 0.4572)
		(drill 0.2032)
		(layers "F.Cu" "B.Cu")
		(net "GND")
	)
	(via
		(at 73.634346 -406.370536)
		(size 0.4572)
		(drill 0.254)
		(layers "F.Cu" "B.Cu")
		(net "GND")
	)
	(via
		(at 116.437156 -412.748476)
		(size 0.508)
		(drill 0.254)
		(layers "F.Cu" "B.Cu")
		(net "GND")
	)
	(via
		(at 368.223038 -201.20991)
		(size 0.6604)
		(drill 0.3302)
		(layers "F.Cu" "B.Cu")
		(net "GND")
	)
	(via
		(at 345.013534 -234.970066)
		(size 0.4572)
		(drill 0.2032)
		(layers "F.Cu" "B.Cu")
		(net "GND")
	)
	(via
		(at 383.654808 -259.616956)
		(size 0.4572)
		(drill 0.2032)
		(layers "F.Cu" "B.Cu")
		(net "GND")
	)
	(via
		(at 373.622316 -103.237284)
		(size 0.508)
		(drill 0.254)
		(layers "F.Cu" "B.Cu")
		(net "GND")
	)
	(via
		(at 39.420546 -246.616728)
		(size 0.4572)
		(drill 0.2032)
		(layers "F.Cu" "B.Cu")
		(net "GND")
	)
	(via
		(at 81.116678 -403.883876)
		(size 0.4064)
		(drill 0.2032)
		(layers "F.Cu" "B.Cu")
		(net "GND")
	)
	(via
		(at 352.918522 -37.556186)
		(size 0.508)
		(drill 0.254)
		(layers "F.Cu" "B.Cu")
		(net "GND")
	)
	(via
		(at 214.615014 -275.516594)
		(size 0.4572)
		(drill 0.2032)
		(layers "F.Cu" "B.Cu")
		(net "GND")
	)
	(via
		(at 122.921014 -331.776832)
		(size 0.49022)
		(drill 0.254)
		(layers "F.Cu" "B.Cu")
		(net "GND")
	)
	(via
		(at 374.617234 -216.25052)
		(size 0.4572)
		(drill 0.2032)
		(layers "F.Cu" "B.Cu")
		(net "GND")
	)
	(via
		(at 104.198928 -424.241976)
		(size 0.508)
		(drill 0.254)
		(layers "F.Cu" "B.Cu")
		(net "GND")
	)
	(via
		(at 127.726948 -266.941808)
		(size 0.4572)
		(drill 0.2032)
		(layers "F.Cu" "B.Cu")
		(net "GND")
	)
	(via
		(at 447.16319 -12.37488)
		(size 0.508)
		(drill 0.254)
		(layers "F.Cu" "B.Cu")
		(net "GND")
	)
	(via
		(at 210.514946 -267.016738)
		(size 0.4572)
		(drill 0.2032)
		(layers "F.Cu" "B.Cu")
		(net "GND")
	)
	(via
		(at 43.520614 -286.56661)
		(size 0.4572)
		(drill 0.2032)
		(layers "F.Cu" "B.Cu")
		(net "GND")
	)
	(via
		(at 46.553882 -351.227898)
		(size 0.508)
		(drill 0.254)
		(layers "F.Cu" "B.Cu")
		(net "GND")
	)
	(via
		(at 439.923682 -233.86669)
		(size 0.4572)
		(drill 0.2032)
		(layers "F.Cu" "B.Cu")
		(net "GND")
	)
	(via
		(at 279.816814 -295.06672)
		(size 0.4572)
		(drill 0.2032)
		(layers "F.Cu" "B.Cu")
		(net "GND")
	)
	(via
		(at 58.666888 -12.37488)
		(size 0.508)
		(drill 0.254)
		(layers "F.Cu" "B.Cu")
		(net "GND")
	)
	(via
		(at 50.379376 -355.531928)
		(size 0.49022)
		(drill 0.254)
		(layers "F.Cu" "B.Cu")
		(net "GND")
	)
	(via
		(at 381.761238 -406.370536)
		(size 0.4572)
		(drill 0.254)
		(layers "F.Cu" "B.Cu")
		(net "GND")
	)
	(via
		(at 385.534916 -257.98907)
		(size 0.4572)
		(drill 0.2032)
		(layers "F.Cu" "B.Cu")
		(net "GND")
	)
	(via
		(at 375.666762 -257.175254)
		(size 0.4572)
		(drill 0.2032)
		(layers "F.Cu" "B.Cu")
		(net "GND")
	)
	(via
		(at 199.527414 -207.51673)
		(size 0.4572)
		(drill 0.2032)
		(layers "F.Cu" "B.Cu")
		(net "GND")
	)
	(via
		(at 113.52022 -243.923058)
		(size 0.4572)
		(drill 0.2032)
		(layers "F.Cu" "B.Cu")
		(net "GND")
	)
	(via
		(at 171.992798 -352.404172)
		(size 0.49022)
		(drill 0.254)
		(layers "F.Cu" "B.Cu")
		(net "GND")
	)
	(via
		(at 329.439778 -40.931846)
		(size 0.4572)
		(drill 0.2032)
		(layers "F.Cu" "B.Cu")
		(net "GND")
	)
	(via
		(at 9.245346 -283.166566)
		(size 0.4572)
		(drill 0.2032)
		(layers "F.Cu" "B.Cu")
		(net "GND")
	)
	(via
		(at 73.634346 -410.664152)
		(size 0.4572)
		(drill 0.254)
		(layers "F.Cu" "B.Cu")
		(net "GND")
	)
	(via
		(at 400.140678 -406.370536)
		(size 0.4572)
		(drill 0.254)
		(layers "F.Cu" "B.Cu")
		(net "GND")
	)
	(via
		(at 212.812884 -319.268856)
		(size 0.4572)
		(drill 0.2032)
		(layers "F.Cu" "B.Cu")
		(net "GND")
	)
	(via
		(at 96.121474 -334.282034)
		(size 0.49022)
		(drill 0.254)
		(layers "F.Cu" "B.Cu")
		(net "GND")
	)
	(via
		(at 445.577214 -236.416596)
		(size 0.4572)
		(drill 0.2032)
		(layers "F.Cu" "B.Cu")
		(net "GND")
	)
	(via
		(at 392.667998 -404.51786)
		(size 0.4572)
		(drill 0.254)
		(layers "F.Cu" "B.Cu")
		(net "GND")
	)
	(via
		(at 23.037292 -415.127948)
		(size 0.508)
		(drill 0.254)
		(layers "F.Cu" "B.Cu")
		(net "GND")
	)
	(via
		(at 430.489614 -281.466798)
		(size 0.4572)
		(drill 0.2032)
		(layers "F.Cu" "B.Cu")
		(net "GND")
	)
	(via
		(at 405.439372 -206.666592)
		(size 0.4572)
		(drill 0.2032)
		(layers "F.Cu" "B.Cu")
		(net "GND")
	)
	(via
		(at 131.015994 -257.98907)
		(size 0.4572)
		(drill 0.2032)
		(layers "F.Cu" "B.Cu")
		(net "GND")
	)
	(via
		(at 209.281014 -204.116686)
		(size 0.4572)
		(drill 0.2032)
		(layers "F.Cu" "B.Cu")
		(net "GND")
	)
	(via
		(at 118.218966 -216.25052)
		(size 0.4572)
		(drill 0.2032)
		(layers "F.Cu" "B.Cu")
		(net "GND")
	)
	(via
		(at 123.497594 -280.778204)
		(size 0.4572)
		(drill 0.2032)
		(layers "F.Cu" "B.Cu")
		(net "GND")
	)
	(via
		(at 43.520614 -233.86669)
		(size 0.4572)
		(drill 0.2032)
		(layers "F.Cu" "B.Cu")
		(net "GND")
	)
	(via
		(at 335.255108 -275.08073)
		(size 0.4572)
		(drill 0.2032)
		(layers "F.Cu" "B.Cu")
		(net "GND")
	)
	(via
		(at 314.092082 -205.816708)
		(size 0.4572)
		(drill 0.2032)
		(layers "F.Cu" "B.Cu")
		(net "GND")
	)
	(via
		(at 415.605214 -276.366732)
		(size 0.4572)
		(drill 0.2032)
		(layers "F.Cu" "B.Cu")
		(net "GND")
	)
	(via
		(at 272.273014 -236.416596)
		(size 0.4572)
		(drill 0.2032)
		(layers "F.Cu" "B.Cu")
		(net "GND")
	)
	(via
		(at 357.700834 -216.25052)
		(size 0.4572)
		(drill 0.2032)
		(layers "F.Cu" "B.Cu")
		(net "GND")
	)
	(via
		(at 383.545334 -220.319854)
		(size 0.4572)
		(drill 0.2032)
		(layers "F.Cu" "B.Cu")
		(net "GND")
	)
	(via
		(at 420.736014 -250.016772)
		(size 0.4572)
		(drill 0.2032)
		(layers "F.Cu" "B.Cu")
		(net "GND")
	)
	(via
		(at 277.607014 -204.96657)
		(size 0.4572)
		(drill 0.2032)
		(layers "F.Cu" "B.Cu")
		(net "GND")
	)
	(via
		(at 27.547062 -12.37488)
		(size 0.508)
		(drill 0.254)
		(layers "F.Cu" "B.Cu")
		(net "GND")
	)
	(via
		(at 276.373082 -213.46668)
		(size 0.4572)
		(drill 0.2032)
		(layers "F.Cu" "B.Cu")
		(net "GND")
	)
	(via
		(at 223.06788 -48.78197)
		(size 0.508)
		(drill 0.254)
		(layers "F.Cu" "B.Cu")
		(net "GND")
	)
	(via
		(at 55.066946 -7.215124)
		(size 0.508)
		(drill 0.254)
		(layers "F.Cu" "B.Cu")
		(net "GND")
	)
	(via
		(at 340.290658 -41.871646)
		(size 0.4572)
		(drill 0.2032)
		(layers "F.Cu" "B.Cu")
		(net "GND")
	)
	(via
		(at 445.577214 -261.916672)
		(size 0.4572)
		(drill 0.2032)
		(layers "F.Cu" "B.Cu")
		(net "GND")
	)
	(via
		(at 33.767014 -202.416664)
		(size 0.4572)
		(drill 0.2032)
		(layers "F.Cu" "B.Cu")
		(net "GND")
	)
	(via
		(at 56.398414 -228.766624)
		(size 0.4572)
		(drill 0.2032)
		(layers "F.Cu" "B.Cu")
		(net "GND")
	)
	(via
		(at 432.379882 -216.866724)
		(size 0.4572)
		(drill 0.2032)
		(layers "F.Cu" "B.Cu")
		(net "GND")
	)
	(via
		(at 444.74638 -370.629688)
		(size 0.49022)
		(drill 0.254)
		(layers "F.Cu" "B.Cu")
		(net "GND")
	)
	(via
		(at 349.71228 -249.620024)
		(size 0.4572)
		(drill 0.2032)
		(layers "F.Cu" "B.Cu")
		(net "GND")
	)
	(via
		(at 96.603312 -247.178322)
		(size 0.4572)
		(drill 0.2032)
		(layers "F.Cu" "B.Cu")
		(net "GND")
	)
	(via
		(at 11.135614 -272.966688)
		(size 0.4572)
		(drill 0.2032)
		(layers "F.Cu" "B.Cu")
		(net "GND")
	)
	(via
		(at 129.026666 -231.714548)
		(size 0.4572)
		(drill 0.2032)
		(layers "F.Cu" "B.Cu")
		(net "GND")
	)
	(via
		(at 73.634346 -407.638504)
		(size 0.4572)
		(drill 0.254)
		(layers "F.Cu" "B.Cu")
		(net "GND")
	)
	(via
		(at 380.445518 -76.453238)
		(size 0.6604)
		(drill 0.3302)
		(layers "F.Cu" "B.Cu")
		(net "GND")
	)
	(via
		(at 420.736014 -227.066602)
		(size 0.4572)
		(drill 0.2032)
		(layers "F.Cu" "B.Cu")
		(net "GND")
	)
	(via
		(at 125.722634 -403.883876)
		(size 0.4064)
		(drill 0.2032)
		(layers "F.Cu" "B.Cu")
		(net "GND")
	)
	(via
		(at 132.315712 -230.900478)
		(size 0.4572)
		(drill 0.2032)
		(layers "F.Cu" "B.Cu")
		(net "GND")
	)
	(via
		(at 128.86944 -35.684968)
		(size 0.508)
		(drill 0.254)
		(layers "F.Cu" "B.Cu")
		(net "GND")
	)
	(via
		(at 309.908956 -403.249892)
		(size 0.4572)
		(drill 0.254)
		(layers "F.Cu" "B.Cu")
		(net "GND")
	)
	(via
		(at 79.023718 -338.62645)
		(size 0.6604)
		(drill 0.3302)
		(layers "F.Cu" "B.Cu")
		(net "GND")
	)
	(via
		(at 364.383828 -329.943714)
		(size 0.508)
		(drill 0.254)
		(layers "F.Cu" "B.Cu")
		(net "GND")
	)
	(via
		(at 175.005746 -295.06672)
		(size 0.4572)
		(drill 0.2032)
		(layers "F.Cu" "B.Cu")
		(net "GND")
	)
	(via
		(at 99.865434 -329.76312)
		(size 0.508)
		(drill 0.254)
		(layers "F.Cu" "B.Cu")
		(net "GND")
	)
	(via
		(at 270.063214 -217.716608)
		(size 0.4572)
		(drill 0.2032)
		(layers "F.Cu" "B.Cu")
		(net "GND")
	)
	(via
		(at 405.634952 -203.266802)
		(size 0.4572)
		(drill 0.2032)
		(layers "F.Cu" "B.Cu")
		(net "GND")
	)
	(via
		(at 29.346906 -9.424924)
		(size 0.508)
		(drill 0.254)
		(layers "F.Cu" "B.Cu")
		(net "GND")
	)
	(via
		(at 56.60263 -4.328668)
		(size 0.508)
		(drill 0.254)
		(layers "F.Cu" "B.Cu")
		(net "GND")
	)
	(via
		(at 424.836082 -210.066636)
		(size 0.4572)
		(drill 0.2032)
		(layers "F.Cu" "B.Cu")
		(net "GND")
	)
	(via
		(at 271.295622 -67.437762)
		(size 0.508)
		(drill 0.254)
		(layers "F.Cu" "B.Cu")
		(net "GND")
	)
	(via
		(at 67.250056 -427.851316)
		(size 0.4572)
		(drill 0.2032)
		(layers "F.Cu" "B.Cu")
		(net "GND")
	)
	(via
		(at 66.152014 -264.466578)
		(size 0.4572)
		(drill 0.2032)
		(layers "F.Cu" "B.Cu")
		(net "GND")
	)
	(via
		(at 306.548282 -233.86669)
		(size 0.4572)
		(drill 0.2032)
		(layers "F.Cu" "B.Cu")
		(net "GND")
	)
	(via
		(at 241.862356 -36.040314)
		(size 0.508)
		(drill 0.254)
		(layers "F.Cu" "B.Cu")
		(net "GND")
	)
	(via
		(at 347.652848 -410.030168)
		(size 0.4064)
		(drill 0.2032)
		(layers "F.Cu" "B.Cu")
		(net "GND")
	)
	(via
		(at 216.824814 -297.616626)
		(size 0.4572)
		(drill 0.2032)
		(layers "F.Cu" "B.Cu")
		(net "GND")
	)
	(via
		(at 290.975542 -361.629452)
		(size 0.49022)
		(drill 0.254)
		(layers "F.Cu" "B.Cu")
		(net "GND")
	)
	(via
		(at 326.845168 -403.883876)
		(size 0.4064)
		(drill 0.2032)
		(layers "F.Cu" "B.Cu")
		(net "GND")
	)
	(via
		(at 153.652982 -401.492212)
		(size 0.4572)
		(drill 0.254)
		(layers "F.Cu" "B.Cu")
		(net "GND")
	)
	(via
		(at 176.896014 -204.116686)
		(size 0.4572)
		(drill 0.2032)
		(layers "F.Cu" "B.Cu")
		(net "GND")
	)
	(via
		(at 184.439814 -289.966654)
		(size 0.4572)
		(drill 0.2032)
		(layers "F.Cu" "B.Cu")
		(net "GND")
	)
	(via
		(at 277.607014 -307.816758)
		(size 0.4572)
		(drill 0.2032)
		(layers "F.Cu" "B.Cu")
		(net "GND")
	)
	(via
		(at 63.726314 -310.366664)
		(size 0.4572)
		(drill 0.2032)
		(layers "F.Cu" "B.Cu")
		(net "GND")
	)
	(via
		(at 268.829282 -226.216718)
		(size 0.4572)
		(drill 0.2032)
		(layers "F.Cu" "B.Cu")
		(net "GND")
	)
	(via
		(at 369.154964 -326.948292)
		(size 0.508)
		(drill 0.254)
		(layers "F.Cu" "B.Cu")
		(net "GND")
	)
	(via
		(at 147.349972 -436.347362)
		(size 0.4572)
		(drill 0.2032)
		(layers "F.Cu" "B.Cu")
		(net "GND")
	)
	(via
		(at 77.746098 -144.708372)
		(size 0.508)
		(drill 0.254)
		(layers "F.Cu" "B.Cu")
		(net "GND")
	)
	(via
		(at 113.519966 -219.506038)
		(size 0.4572)
		(drill 0.2032)
		(layers "F.Cu" "B.Cu")
		(net "GND")
	)
	(via
		(at 180.339746 -273.816572)
		(size 0.4572)
		(drill 0.2032)
		(layers "F.Cu" "B.Cu")
		(net "GND")
	)
	(via
		(at 375.447306 -167.866568)
		(size 0.508)
		(drill 0.254)
		(layers "F.Cu" "B.Cu")
		(net "GND")
	)
	(via
		(at 76.697586 -410.664152)
		(size 0.4572)
		(drill 0.254)
		(layers "F.Cu" "B.Cu")
		(net "GND")
	)
	(via
		(at 184.439814 -238.116618)
		(size 0.4572)
		(drill 0.2032)
		(layers "F.Cu" "B.Cu")
		(net "GND")
	)
	(via
		(at 134.815326 -409.396184)
		(size 0.4572)
		(drill 0.254)
		(layers "F.Cu" "B.Cu")
		(net "GND")
	)
	(via
		(at 63.942214 -224.516696)
		(size 0.4572)
		(drill 0.2032)
		(layers "F.Cu" "B.Cu")
		(net "GND")
	)
	(via
		(at 339.37448 -246.364506)
		(size 0.4572)
		(drill 0.2032)
		(layers "F.Cu" "B.Cu")
		(net "GND")
	)
	(via
		(at 117.86108 -401.424648)
		(size 0.508)
		(drill 0.254)
		(layers "F.Cu" "B.Cu")
		(net "GND")
	)
	(via
		(at 95.69958 -98.367088)
		(size 0.508)
		(drill 0.254)
		(layers "F.Cu" "B.Cu")
		(net "GND")
	)
	(via
		(at 334.205834 -232.528364)
		(size 0.4572)
		(drill 0.2032)
		(layers "F.Cu" "B.Cu")
		(net "GND")
	)
	(via
		(at 420.736014 -246.616728)
		(size 0.4572)
		(drill 0.2032)
		(layers "F.Cu" "B.Cu")
		(net "GND")
	)
	(via
		(at 85.905594 -259.616956)
		(size 0.4318)
		(drill 0.2032)
		(layers "F.Cu" "B.Cu")
		(net "GND")
	)
	(via
		(at 209.727292 -35.321748)
		(size 0.508)
		(drill 0.254)
		(layers "F.Cu" "B.Cu")
		(net "GND")
	)
	(via
		(at 48.918876 -322.900548)
		(size 0.4572)
		(drill 0.2032)
		(layers "F.Cu" "B.Cu")
		(net "GND")
	)
	(via
		(at 191.983614 -262.76681)
		(size 0.4572)
		(drill 0.2032)
		(layers "F.Cu" "B.Cu")
		(net "GND")
	)
	(via
		(at 210.54314 -338.266024)
		(size 0.508)
		(drill 0.254)
		(layers "F.Cu" "B.Cu")
		(net "GND")
	)
	(via
		(at 427.766988 -9.424924)
		(size 0.508)
		(drill 0.254)
		(layers "F.Cu" "B.Cu")
		(net "GND")
	)
	(via
		(at 274.163282 -202.416664)
		(size 0.4572)
		(drill 0.2032)
		(layers "F.Cu" "B.Cu")
		(net "GND")
	)
	(via
		(at 91.904566 -219.506038)
		(size 0.4572)
		(drill 0.2032)
		(layers "F.Cu" "B.Cu")
		(net "GND")
	)
	(via
		(at 39.3954 -437.708548)
		(size 0.508)
		(drill 0.254)
		(layers "F.Cu" "B.Cu")
		(net "GND")
	)
	(via
		(at 127.288544 -79.308452)
		(size 0.508)
		(drill 0.254)
		(layers "F.Cu" "B.Cu")
		(net "GND")
	)
	(via
		(at 424.836082 -244.066568)
		(size 0.4572)
		(drill 0.2032)
		(layers "F.Cu" "B.Cu")
		(net "GND")
	)
	(via
		(at 41.310814 -297.616626)
		(size 0.4572)
		(drill 0.2032)
		(layers "F.Cu" "B.Cu")
		(net "GND")
	)
	(via
		(at 290.857432 -375.089928)
		(size 0.508)
		(drill 0.254)
		(layers "F.Cu" "B.Cu")
		(net "GND")
	)
	(via
		(at 19.17446 -109.859826)
		(size 0.508)
		(drill 0.254)
		(layers "F.Cu" "B.Cu")
		(net "GND")
	)
	(via
		(at 47.421038 -403.883876)
		(size 0.4064)
		(drill 0.2032)
		(layers "F.Cu" "B.Cu")
		(net "GND")
	)
	(via
		(at 175.005746 -281.466798)
		(size 0.4572)
		(drill 0.2032)
		(layers "F.Cu" "B.Cu")
		(net "GND")
	)
	(via
		(at 427.045882 -306.96662)
		(size 0.4572)
		(drill 0.2032)
		(layers "F.Cu" "B.Cu")
		(net "GND")
	)
	(via
		(at 90.964766 -222.761556)
		(size 0.4572)
		(drill 0.2032)
		(layers "F.Cu" "B.Cu")
		(net "GND")
	)
	(via
		(at 304.338482 -196.466714)
		(size 0.4572)
		(drill 0.2032)
		(layers "F.Cu" "B.Cu")
		(net "GND")
	)
	(via
		(at 432.379882 -272.966688)
		(size 0.4572)
		(drill 0.2032)
		(layers "F.Cu" "B.Cu")
		(net "GND")
	)
	(via
		(at 292.694614 -287.416748)
		(size 0.4572)
		(drill 0.2032)
		(layers "F.Cu" "B.Cu")
		(net "GND")
	)
	(via
		(at 52.10429 -403.249892)
		(size 0.4572)
		(drill 0.254)
		(layers "F.Cu" "B.Cu")
		(net "GND")
	)
	(via
		(at 449.892166 -73.930256)
		(size 0.508)
		(drill 0.254)
		(layers "F.Cu" "B.Cu")
		(net "GND")
	)
	(via
		(at 276.373082 -267.866622)
		(size 0.4572)
		(drill 0.2032)
		(layers "F.Cu" "B.Cu")
		(net "GND")
	)
	(via
		(at 18.679414 -202.416664)
		(size 0.4572)
		(drill 0.2032)
		(layers "F.Cu" "B.Cu")
		(net "GND")
	)
	(via
		(at 66.152014 -244.066568)
		(size 0.4572)
		(drill 0.2032)
		(layers "F.Cu" "B.Cu")
		(net "GND")
	)
	(via
		(at 67.146678 -407.00452)
		(size 0.4064)
		(drill 0.2032)
		(layers "F.Cu" "B.Cu")
		(net "GND")
	)
	(via
		(at 390.863582 -401.492212)
		(size 0.4572)
		(drill 0.254)
		(layers "F.Cu" "B.Cu")
		(net "GND")
	)
	(via
		(at 176.896014 -226.216718)
		(size 0.4572)
		(drill 0.2032)
		(layers "F.Cu" "B.Cu")
		(net "GND")
	)
	(via
		(at 63.098426 -404.51786)
		(size 0.4572)
		(drill 0.254)
		(layers "F.Cu" "B.Cu")
		(net "GND")
	)
	(via
		(at 186.649614 -275.516594)
		(size 0.4572)
		(drill 0.2032)
		(layers "F.Cu" "B.Cu")
		(net "GND")
	)
	(via
		(at 344.906092 -331.776832)
		(size 0.49022)
		(drill 0.254)
		(layers "F.Cu" "B.Cu")
		(net "GND")
	)
	(via
		(at 169.352214 -266.1666)
		(size 0.4572)
		(drill 0.2032)
		(layers "F.Cu" "B.Cu")
		(net "GND")
	)
	(via
		(at 464.764882 -288.266632)
		(size 0.4572)
		(drill 0.2032)
		(layers "F.Cu" "B.Cu")
		(net "GND")
	)
	(via
		(at 35.976814 -277.216616)
		(size 0.4572)
		(drill 0.2032)
		(layers "F.Cu" "B.Cu")
		(net "GND")
	)
	(via
		(at 190.093346 -304.416714)
		(size 0.4572)
		(drill 0.2032)
		(layers "F.Cu" "B.Cu")
		(net "GND")
	)
	(via
		(at 122.087894 -283.219906)
		(size 0.4572)
		(drill 0.2032)
		(layers "F.Cu" "B.Cu")
		(net "GND")
	)
	(via
		(at 108.737146 -402.915628)
		(size 0.508)
		(drill 0.254)
		(layers "F.Cu" "B.Cu")
		(net "GND")
	)
	(via
		(at 250.194064 -87.543386)
		(size 0.508)
		(drill 0.254)
		(layers "F.Cu" "B.Cu")
		(net "GND")
	)
	(via
		(at 130.906012 -228.45903)
		(size 0.4572)
		(drill 0.2032)
		(layers "F.Cu" "B.Cu")
		(net "GND")
	)
	(via
		(at 56.83885 -149.283674)
		(size 0.49022)
		(drill 0.254)
		(layers "F.Cu" "B.Cu")
		(net "GND")
	)
	(via
		(at 110.700566 -216.25052)
		(size 0.4572)
		(drill 0.2032)
		(layers "F.Cu" "B.Cu")
		(net "GND")
	)
	(via
		(at 339.374734 -217.064336)
		(size 0.4572)
		(drill 0.2032)
		(layers "F.Cu" "B.Cu")
		(net "GND")
	)
	(via
		(at 449.584318 -178.09845)
		(size 0.6604)
		(drill 0.3302)
		(layers "F.Cu" "B.Cu")
		(net "GND")
	)
	(via
		(at 373.677434 -243.922804)
		(size 0.4572)
		(drill 0.2032)
		(layers "F.Cu" "B.Cu")
		(net "GND")
	)
	(via
		(at 94.364048 -256.361438)
		(size 0.4572)
		(drill 0.2032)
		(layers "F.Cu" "B.Cu")
		(net "GND")
	)
	(via
		(at 375.667016 -270.19758)
		(size 0.4572)
		(drill 0.2032)
		(layers "F.Cu" "B.Cu")
		(net "GND")
	)
	(via
		(at 179.105814 -247.466612)
		(size 0.4572)
		(drill 0.2032)
		(layers "F.Cu" "B.Cu")
		(net "GND")
	)
	(via
		(at 325.225156 -404.51786)
		(size 0.4572)
		(drill 0.254)
		(layers "F.Cu" "B.Cu")
		(net "GND")
	)
	(via
		(at 340.250018 -436.347362)
		(size 0.4572)
		(drill 0.2032)
		(layers "F.Cu" "B.Cu")
		(net "GND")
	)
	(via
		(at 306.03952 -191.524128)
		(size 0.508)
		(drill 0.254)
		(layers "F.Cu" "B.Cu")
		(net "GND")
	)
	(via
		(at 127.257048 -257.98907)
		(size 0.4572)
		(drill 0.2032)
		(layers "F.Cu" "B.Cu")
		(net "GND")
	)
	(via
		(at 51.064414 -250.866656)
		(size 0.4572)
		(drill 0.2032)
		(layers "F.Cu" "B.Cu")
		(net "GND")
	)
	(via
		(at 334.25003 -433.747164)
		(size 0.4572)
		(drill 0.2032)
		(layers "F.Cu" "B.Cu")
		(net "GND")
	)
	(via
		(at 385.911344 -77.070204)
		(size 0.508)
		(drill 0.254)
		(layers "F.Cu" "B.Cu")
		(net "GND")
	)
	(via
		(at 235.42752 -388.01294)
		(size 0.508)
		(drill 0.254)
		(layers "F.Cu" "B.Cu")
		(net "GND")
	)
	(via
		(at 401.349972 -433.747164)
		(size 0.4572)
		(drill 0.2032)
		(layers "F.Cu" "B.Cu")
		(net "GND")
	)
	(via
		(at 85.887306 -407.638504)
		(size 0.4572)
		(drill 0.254)
		(layers "F.Cu" "B.Cu")
		(net "GND")
	)
	(via
		(at 332.693518 -47.510446)
		(size 0.4572)
		(drill 0.2032)
		(layers "F.Cu" "B.Cu")
		(net "GND")
	)
	(via
		(at 103.761794 -284.033722)
		(size 0.4572)
		(drill 0.2032)
		(layers "F.Cu" "B.Cu")
		(net "GND")
	)
	(via
		(at 175.005746 -263.616694)
		(size 0.4572)
		(drill 0.2032)
		(layers "F.Cu" "B.Cu")
		(net "GND")
	)
	(via
		(at 289.250882 -271.266666)
		(size 0.4572)
		(drill 0.2032)
		(layers "F.Cu" "B.Cu")
		(net "GND")
	)
	(via
		(at 39.420546 -281.466798)
		(size 0.4572)
		(drill 0.2032)
		(layers "F.Cu" "B.Cu")
		(net "GND")
	)
	(via
		(at 374.904 -353.828858)
		(size 0.508)
		(drill 0.254)
		(layers "F.Cu" "B.Cu")
		(net "GND")
	)
	(via
		(at 180.339746 -283.166566)
		(size 0.4572)
		(drill 0.2032)
		(layers "F.Cu" "B.Cu")
		(net "GND")
	)
	(via
		(at 339.484462 -261.244842)
		(size 0.4572)
		(drill 0.2032)
		(layers "F.Cu" "B.Cu")
		(net "GND")
	)
	(via
		(at 155.349956 -435.0512)
		(size 0.4572)
		(drill 0.2032)
		(layers "F.Cu" "B.Cu")
		(net "GND")
	)
	(via
		(at 446.274952 -394.876274)
		(size 0.6604)
		(drill 0.3302)
		(layers "F.Cu" "B.Cu")
		(net "GND")
	)
	(via
		(at 422.55186 -359.414572)
		(size 0.508)
		(drill 0.254)
		(layers "F.Cu" "B.Cu")
		(net "GND")
	)
	(via
		(at 195.427346 -225.36658)
		(size 0.4572)
		(drill 0.2032)
		(layers "F.Cu" "B.Cu")
		(net "GND")
	)
	(via
		(at 101.302312 -234.15625)
		(size 0.4572)
		(drill 0.2032)
		(layers "F.Cu" "B.Cu")
		(net "GND")
	)
	(via
		(at 299.004482 -202.416664)
		(size 0.4572)
		(drill 0.2032)
		(layers "F.Cu" "B.Cu")
		(net "GND")
	)
	(via
		(at 299.004482 -200.716642)
		(size 0.4572)
		(drill 0.2032)
		(layers "F.Cu" "B.Cu")
		(net "GND")
	)
	(via
		(at 119.685816 -257.69316)
		(size 0.4572)
		(drill 0.2032)
		(layers "F.Cu" "B.Cu")
		(net "GND")
	)
	(via
		(at 419.502082 -295.916604)
		(size 0.4572)
		(drill 0.2032)
		(layers "F.Cu" "B.Cu")
		(net "GND")
	)
	(via
		(at 416.575494 -180.964078)
		(size 0.49022)
		(drill 0.254)
		(layers "F.Cu" "B.Cu")
		(net "GND")
	)
	(via
		(at 383.185162 -283.219906)
		(size 0.4572)
		(drill 0.2032)
		(layers "F.Cu" "B.Cu")
		(net "GND")
	)
	(via
		(at 370.967762 -262.058658)
		(size 0.4572)
		(drill 0.2032)
		(layers "F.Cu" "B.Cu")
		(net "GND")
	)
	(via
		(at 47.811182 -351.644458)
		(size 0.508)
		(drill 0.254)
		(layers "F.Cu" "B.Cu")
		(net "GND")
	)
	(via
		(at 33.35909 -18.246344)
		(size 0.508)
		(drill 0.254)
		(layers "F.Cu" "B.Cu")
		(net "GND")
	)
	(via
		(at 307.782214 -203.266802)
		(size 0.4572)
		(drill 0.2032)
		(layers "F.Cu" "B.Cu")
		(net "GND")
	)
	(via
		(at 169.352214 -297.616626)
		(size 0.4572)
		(drill 0.2032)
		(layers "F.Cu" "B.Cu")
		(net "GND")
	)
	(via
		(at 9.245346 -201.56678)
		(size 0.4572)
		(drill 0.2032)
		(layers "F.Cu" "B.Cu")
		(net "GND")
	)
	(via
		(at 167.461946 -289.11677)
		(size 0.4572)
		(drill 0.2032)
		(layers "F.Cu" "B.Cu")
		(net "GND")
	)
	(via
		(at 390.349994 -432.747166)
		(size 0.4572)
		(drill 0.2032)
		(layers "F.Cu" "B.Cu")
		(net "GND")
	)
	(via
		(at 63.942214 -239.81664)
		(size 0.4572)
		(drill 0.2032)
		(layers "F.Cu" "B.Cu")
		(net "GND")
	)
	(via
		(at 377.546362 -263.686544)
		(size 0.4572)
		(drill 0.2032)
		(layers "F.Cu" "B.Cu")
		(net "GND")
	)
	(via
		(at 152.914858 -193.40703)
		(size 0.508)
		(drill 0.254)
		(layers "F.Cu" "B.Cu")
		(net "GND")
	)
	(via
		(at 352.104198 -67.46748)
		(size 0.508)
		(drill 0.254)
		(layers "F.Cu" "B.Cu")
		(net "GND")
	)
	(via
		(at 133.820662 -131.271518)
		(size 0.508)
		(drill 0.254)
		(layers "F.Cu" "B.Cu")
		(net "GND")
	)
	(via
		(at 18.679414 -271.266666)
		(size 0.4572)
		(drill 0.2032)
		(layers "F.Cu" "B.Cu")
		(net "GND")
	)
	(via
		(at 131.955794 -277.522432)
		(size 0.4572)
		(drill 0.2032)
		(layers "F.Cu" "B.Cu")
		(net "GND")
	)
	(via
		(at 53.256942 -18.502376)
		(size 0.508)
		(drill 0.254)
		(layers "F.Cu" "B.Cu")
		(net "GND")
	)
	(via
		(at 156.01188 -115.026948)
		(size 0.508)
		(drill 0.254)
		(layers "F.Cu" "B.Cu")
		(net "GND")
	)
	(via
		(at 35.976814 -288.266632)
		(size 0.4572)
		(drill 0.2032)
		(layers "F.Cu" "B.Cu")
		(net "GND")
	)
	(via
		(at 374.617234 -237.411514)
		(size 0.4572)
		(drill 0.2032)
		(layers "F.Cu" "B.Cu")
		(net "GND")
	)
	(via
		(at 370.497862 -282.405836)
		(size 0.4572)
		(drill 0.2032)
		(layers "F.Cu" "B.Cu")
		(net "GND")
	)
	(via
		(at 268.829282 -194.766692)
		(size 0.4572)
		(drill 0.2032)
		(layers "F.Cu" "B.Cu")
		(net "GND")
	)
	(via
		(at 302.448214 -206.666592)
		(size 0.4572)
		(drill 0.2032)
		(layers "F.Cu" "B.Cu")
		(net "GND")
	)
	(via
		(at 307.782214 -281.466798)
		(size 0.4572)
		(drill 0.2032)
		(layers "F.Cu" "B.Cu")
		(net "GND")
	)
	(via
		(at 274.163282 -230.466646)
		(size 0.4572)
		(drill 0.2032)
		(layers "F.Cu" "B.Cu")
		(net "GND")
	)
	(via
		(at 413.966152 -323.429376)
		(size 0.4572)
		(drill 0.2032)
		(layers "F.Cu" "B.Cu")
		(net "GND")
	)
	(via
		(at 447.467482 -272.966688)
		(size 0.4572)
		(drill 0.2032)
		(layers "F.Cu" "B.Cu")
		(net "GND")
	)
	(via
		(at 7.264654 -415.935414)
		(size 0.508)
		(drill 0.254)
		(layers "F.Cu" "B.Cu")
		(net "GND")
	)
	(via
		(at 415.041334 -4.317746)
		(size 0.508)
		(drill 0.254)
		(layers "F.Cu" "B.Cu")
		(net "GND")
	)
	(via
		(at 377.25477 -407.00452)
		(size 0.4064)
		(drill 0.2032)
		(layers "F.Cu" "B.Cu")
		(net "GND")
	)
	(via
		(at 126.03988 -335.89976)
		(size 0.508)
		(drill 0.254)
		(layers "F.Cu" "B.Cu")
		(net "GND")
	)
	(via
		(at 312.972196 -401.492212)
		(size 0.4572)
		(drill 0.254)
		(layers "F.Cu" "B.Cu")
		(net "GND")
	)
	(via
		(at 109.729524 -92.365576)
		(size 0.508)
		(drill 0.254)
		(layers "F.Cu" "B.Cu")
		(net "GND")
	)
	(via
		(at 209.281014 -219.41663)
		(size 0.4572)
		(drill 0.2032)
		(layers "F.Cu" "B.Cu")
		(net "GND")
	)
	(via
		(at 194.193414 -310.366664)
		(size 0.4572)
		(drill 0.2032)
		(layers "F.Cu" "B.Cu")
		(net "GND")
	)
	(via
		(at 294.904414 -285.716726)
		(size 0.4572)
		(drill 0.2032)
		(layers "F.Cu" "B.Cu")
		(net "GND")
	)
	(via
		(at 195.427346 -304.416714)
		(size 0.4572)
		(drill 0.2032)
		(layers "F.Cu" "B.Cu")
		(net "GND")
	)
	(via
		(at 76.61021 -404.51786)
		(size 0.4572)
		(drill 0.254)
		(layers "F.Cu" "B.Cu")
		(net "GND")
	)
	(via
		(at 272.273014 -295.06672)
		(size 0.4572)
		(drill 0.2032)
		(layers "F.Cu" "B.Cu")
		(net "GND")
	)
	(via
		(at 123.027948 -257.175254)
		(size 0.4572)
		(drill 0.2032)
		(layers "F.Cu" "B.Cu")
		(net "GND")
	)
	(via
		(at 212.724746 -220.266768)
		(size 0.4572)
		(drill 0.2032)
		(layers "F.Cu" "B.Cu")
		(net "GND")
	)
	(via
		(at 447.467482 -271.266666)
		(size 0.4572)
		(drill 0.2032)
		(layers "F.Cu" "B.Cu")
		(net "GND")
	)
	(via
		(at 16.789146 -263.616694)
		(size 0.4572)
		(drill 0.2032)
		(layers "F.Cu" "B.Cu")
		(net "GND")
	)
	(via
		(at 270.063214 -210.916774)
		(size 0.4572)
		(drill 0.2032)
		(layers "F.Cu" "B.Cu")
		(net "GND")
	)
	(via
		(at 443.933072 -0.76454)
		(size 0.508)
		(drill 0.254)
		(layers "F.Cu" "B.Cu")
		(net "GND")
	)
	(via
		(at 228.107748 -248.069608)
		(size 0.508)
		(drill 0.254)
		(layers "F.Cu" "B.Cu")
		(net "GND")
	)
	(via
		(at 432.928776 -103.38943)
		(size 0.508)
		(drill 0.254)
		(layers "F.Cu" "B.Cu")
		(net "GND")
	)
	(via
		(at 377.436634 -216.25052)
		(size 0.4572)
		(drill 0.2032)
		(layers "F.Cu" "B.Cu")
		(net "GND")
	)
	(via
		(at 405.648414 -276.366732)
		(size 0.4572)
		(drill 0.2032)
		(layers "F.Cu" "B.Cu")
		(net "GND")
	)
	(via
		(at 455.011282 -207.51673)
		(size 0.4572)
		(drill 0.2032)
		(layers "F.Cu" "B.Cu")
		(net "GND")
	)
	(via
		(at 409.748482 -303.566576)
		(size 0.4572)
		(drill 0.2032)
		(layers "F.Cu" "B.Cu")
		(net "GND")
	)
	(via
		(at 103.50246 -55.095648)
		(size 0.508)
		(drill 0.254)
		(layers "F.Cu" "B.Cu")
		(net "GND")
	)
	(via
		(at 328.400664 -343.542874)
		(size 0.49022)
		(drill 0.254)
		(layers "F.Cu" "B.Cu")
		(net "GND")
	)
	(via
		(at 76.250038 -432.747166)
		(size 0.4572)
		(drill 0.2032)
		(layers "F.Cu" "B.Cu")
		(net "GND")
	)
	(via
		(at 119.738394 -266.128246)
		(size 0.4572)
		(drill 0.2032)
		(layers "F.Cu" "B.Cu")
		(net "GND")
	)
	(via
		(at 182.549546 -223.666558)
		(size 0.4572)
		(drill 0.2032)
		(layers "F.Cu" "B.Cu")
		(net "GND")
	)
	(via
		(at 179.105814 -262.76681)
		(size 0.4572)
		(drill 0.2032)
		(layers "F.Cu" "B.Cu")
		(net "GND")
	)
	(via
		(at 106.111294 -283.219906)
		(size 0.4572)
		(drill 0.2032)
		(layers "F.Cu" "B.Cu")
		(net "GND")
	)
	(via
		(at 109.760512 -214.546434)
		(size 0.4572)
		(drill 0.2032)
		(layers "F.Cu" "B.Cu")
		(net "GND")
	)
	(via
		(at 366.738662 -280.778204)
		(size 0.4572)
		(drill 0.2032)
		(layers "F.Cu" "B.Cu")
		(net "GND")
	)
	(via
		(at 22.123146 -272.116804)
		(size 0.4572)
		(drill 0.2032)
		(layers "F.Cu" "B.Cu")
		(net "GND")
	)
	(via
		(at 376.073416 -339.114638)
		(size 0.49022)
		(drill 0.254)
		(layers "F.Cu" "B.Cu")
		(net "GND")
	)
	(via
		(at 48.854614 -295.916604)
		(size 0.4572)
		(drill 0.2032)
		(layers "F.Cu" "B.Cu")
		(net "GND")
	)
	(via
		(at 375.557034 -239.0394)
		(size 0.4572)
		(drill 0.2032)
		(layers "F.Cu" "B.Cu")
		(net "GND")
	)
	(via
		(at 15.953232 -106.27995)
		(size 0.508)
		(drill 0.254)
		(layers "F.Cu" "B.Cu")
		(net "GND")
	)
	(via
		(at 378.956062 -282.405836)
		(size 0.4572)
		(drill 0.2032)
		(layers "F.Cu" "B.Cu")
		(net "GND")
	)
	(via
		(at 254.975614 -317.166752)
		(size 0.4572)
		(drill 0.2032)
		(layers "F.Cu" "B.Cu")
		(net "GND")
	)
	(via
		(at 366.04575 -14.569948)
		(size 0.508)
		(drill 0.254)
		(layers "F.Cu" "B.Cu")
		(net "GND")
	)
	(via
		(at 56.83885 -165.742874)
		(size 0.49022)
		(drill 0.254)
		(layers "F.Cu" "B.Cu")
		(net "GND")
	)
	(via
		(at 165.252146 -225.36658)
		(size 0.4572)
		(drill 0.2032)
		(layers "F.Cu" "B.Cu")
		(net "GND")
	)
	(via
		(at 365.219234 -219.506038)
		(size 0.4572)
		(drill 0.2032)
		(layers "F.Cu" "B.Cu")
		(net "GND")
	)
	(via
		(at 382.245616 -260.430772)
		(size 0.4572)
		(drill 0.2032)
		(layers "F.Cu" "B.Cu")
		(net "GND")
	)
	(via
		(at 132.785612 -241.481102)
		(size 0.4572)
		(drill 0.2032)
		(layers "F.Cu" "B.Cu")
		(net "GND")
	)
	(via
		(at 127.616966 -248.806208)
		(size 0.4572)
		(drill 0.2032)
		(layers "F.Cu" "B.Cu")
		(net "GND")
	)
	(via
		(at 442.133482 -262.76681)
		(size 0.4572)
		(drill 0.2032)
		(layers "F.Cu" "B.Cu")
		(net "GND")
	)
	(via
		(at 443.367414 -197.316598)
		(size 0.4572)
		(drill 0.2032)
		(layers "F.Cu" "B.Cu")
		(net "GND")
	)
	(via
		(at 73.83272 -189.309248)
		(size 0.508)
		(drill 0.254)
		(layers "F.Cu" "B.Cu")
		(net "GND")
	)
	(via
		(at 99.532948 -271.825212)
		(size 0.4572)
		(drill 0.2032)
		(layers "F.Cu" "B.Cu")
		(net "GND")
	)
	(via
		(at 375.667016 -276.708616)
		(size 0.4572)
		(drill 0.2032)
		(layers "F.Cu" "B.Cu")
		(net "GND")
	)
	(via
		(at 159.918146 -304.416714)
		(size 0.4572)
		(drill 0.2032)
		(layers "F.Cu" "B.Cu")
		(net "GND")
	)
	(via
		(at 48.99533 -441.225432)
		(size 0.508)
		(drill 0.254)
		(layers "F.Cu" "B.Cu")
		(net "GND")
	)
	(via
		(at 186.876182 -28.444952)
		(size 0.508)
		(drill 0.254)
		(layers "F.Cu" "B.Cu")
		(net "GND")
	)
	(via
		(at 462.555082 -301.01667)
		(size 0.4572)
		(drill 0.2032)
		(layers "F.Cu" "B.Cu")
		(net "GND")
	)
	(via
		(at 51.064414 -275.516594)
		(size 0.4572)
		(drill 0.2032)
		(layers "F.Cu" "B.Cu")
		(net "GND")
	)
	(via
		(at 211.288884 -323.434456)
		(size 0.4572)
		(drill 0.2032)
		(layers "F.Cu" "B.Cu")
		(net "GND")
	)
	(via
		(at 311.666382 -216.866724)
		(size 0.4572)
		(drill 0.2032)
		(layers "F.Cu" "B.Cu")
		(net "GND")
	)
	(via
		(at 449.677282 -275.516594)
		(size 0.4572)
		(drill 0.2032)
		(layers "F.Cu" "B.Cu")
		(net "GND")
	)
	(via
		(at 98.592894 -265.314176)
		(size 0.4572)
		(drill 0.2032)
		(layers "F.Cu" "B.Cu")
		(net "GND")
	)
	(via
		(at 43.520614 -213.46668)
		(size 0.4572)
		(drill 0.2032)
		(layers "F.Cu" "B.Cu")
		(net "GND")
	)
	(via
		(at 169.149014 -275.516594)
		(size 0.4572)
		(drill 0.2032)
		(layers "F.Cu" "B.Cu")
		(net "GND")
	)
	(via
		(at 170.555666 -117.375432)
		(size 0.4572)
		(drill 0.254)
		(layers "F.Cu" "B.Cu")
		(net "GND")
	)
	(via
		(at 110.483396 -356.943406)
		(size 0.508)
		(drill 0.254)
		(layers "F.Cu" "B.Cu")
		(net "GND")
	)
	(via
		(at 371.797834 -216.25052)
		(size 0.4572)
		(drill 0.2032)
		(layers "F.Cu" "B.Cu")
		(net "GND")
	)
	(via
		(at 373.830342 -407.638504)
		(size 0.4572)
		(drill 0.254)
		(layers "F.Cu" "B.Cu")
		(net "GND")
	)
	(via
		(at 442.133482 -219.41663)
		(size 0.4572)
		(drill 0.2032)
		(layers "F.Cu" "B.Cu")
		(net "GND")
	)
	(via
		(at 119.957342 -401.492212)
		(size 0.4572)
		(drill 0.254)
		(layers "F.Cu" "B.Cu")
		(net "GND")
	)
	(via
		(at 259.588508 -67.904868)
		(size 0.508)
		(drill 0.254)
		(layers "F.Cu" "B.Cu")
		(net "GND")
	)
	(via
		(at 168.854628 -350.172528)
		(size 0.508)
		(drill 0.254)
		(layers "F.Cu" "B.Cu")
		(net "GND")
	)
	(via
		(at 447.98742 -376.862848)
		(size 0.49022)
		(drill 0.254)
		(layers "F.Cu" "B.Cu")
		(net "GND")
	)
	(via
		(at 217.001852 -71.126858)
		(size 0.508)
		(drill 0.254)
		(layers "F.Cu" "B.Cu")
		(net "GND")
	)
	(via
		(at 35.976814 -264.466578)
		(size 0.4572)
		(drill 0.2032)
		(layers "F.Cu" "B.Cu")
		(net "GND")
	)
	(via
		(at 135.714994 -271.011396)
		(size 0.4572)
		(drill 0.2032)
		(layers "F.Cu" "B.Cu")
		(net "GND")
	)
	(via
		(at 432.379882 -228.766624)
		(size 0.4572)
		(drill 0.2032)
		(layers "F.Cu" "B.Cu")
		(net "GND")
	)
	(via
		(at 0.76454 -66.880232)
		(size 0.508)
		(drill 0.254)
		(layers "F.Cu" "B.Cu")
		(net "GND")
	)
	(via
		(at 461.87614 -387.55701)
		(size 0.508)
		(drill 0.254)
		(layers "F.Cu" "B.Cu")
		(net "GND")
	)
	(via
		(at 285.150814 -292.516814)
		(size 0.4572)
		(drill 0.2032)
		(layers "F.Cu" "B.Cu")
		(net "GND")
	)
	(via
		(at 263.12368 -108.956348)
		(size 0.508)
		(drill 0.254)
		(layers "F.Cu" "B.Cu")
		(net "GND")
	)
	(via
		(at 334.25003 -434.899562)
		(size 0.4572)
		(drill 0.2032)
		(layers "F.Cu" "B.Cu")
		(net "GND")
	)
	(via
		(at 287.360614 -231.316784)
		(size 0.4572)
		(drill 0.2032)
		(layers "F.Cu" "B.Cu")
		(net "GND")
	)
	(via
		(at 19.84248 -386.419344)
		(size 0.508)
		(drill 0.254)
		(layers "F.Cu" "B.Cu")
		(net "GND")
	)
	(via
		(at 413.349948 -432.451256)
		(size 0.4572)
		(drill 0.2032)
		(layers "F.Cu" "B.Cu")
		(net "GND")
	)
	(via
		(at 48.854614 -297.616626)
		(size 0.4572)
		(drill 0.2032)
		(layers "F.Cu" "B.Cu")
		(net "GND")
	)
	(via
		(at 154.106626 -64.761364)
		(size 0.508)
		(drill 0.254)
		(layers "F.Cu" "B.Cu")
		(net "GND")
	)
	(via
		(at 347.92666 -401.492212)
		(size 0.4572)
		(drill 0.254)
		(layers "F.Cu" "B.Cu")
		(net "GND")
	)
	(via
		(at 227.17125 -232.077768)
		(size 0.508)
		(drill 0.254)
		(layers "F.Cu" "B.Cu")
		(net "GND")
	)
	(via
		(at 358.170734 -226.831144)
		(size 0.4572)
		(drill 0.2032)
		(layers "F.Cu" "B.Cu")
		(net "GND")
	)
	(via
		(at 462.555082 -297.616626)
		(size 0.4572)
		(drill 0.2032)
		(layers "F.Cu" "B.Cu")
		(net "GND")
	)
	(via
		(at 193.48958 -430.618138)
		(size 0.508)
		(drill 0.254)
		(layers "F.Cu" "B.Cu")
		(net "GND")
	)
	(via
		(at 147.349972 -425.547282)
		(size 0.4572)
		(drill 0.2032)
		(layers "F.Cu" "B.Cu")
		(net "GND")
	)
	(via
		(at 408.061414 -283.166566)
		(size 0.4572)
		(drill 0.2032)
		(layers "F.Cu" "B.Cu")
		(net "GND")
	)
	(via
		(at 16.789146 -227.066602)
		(size 0.4572)
		(drill 0.2032)
		(layers "F.Cu" "B.Cu")
		(net "GND")
	)
	(via
		(at 176.896014 -316.316614)
		(size 0.4572)
		(drill 0.2032)
		(layers "F.Cu" "B.Cu")
		(net "GND")
	)
	(via
		(at 449.677282 -271.266666)
		(size 0.4572)
		(drill 0.2032)
		(layers "F.Cu" "B.Cu")
		(net "GND")
	)
	(via
		(at 43.520614 -194.766692)
		(size 0.4572)
		(drill 0.2032)
		(layers "F.Cu" "B.Cu")
		(net "GND")
	)
	(via
		(at 110.952788 -292.95598)
		(size 0.508)
		(drill 0.254)
		(layers "F.Cu" "B.Cu")
		(net "GND")
	)
	(via
		(at 13.345414 -310.366664)
		(size 0.4572)
		(drill 0.2032)
		(layers "F.Cu" "B.Cu")
		(net "GND")
	)
	(via
		(at 35.976814 -207.51673)
		(size 0.4572)
		(drill 0.2032)
		(layers "F.Cu" "B.Cu")
		(net "GND")
	)
	(via
		(at 296.347388 -161.596324)
		(size 0.508)
		(drill 0.254)
		(layers "F.Cu" "B.Cu")
		(net "GND")
	)
	(via
		(at 58.608214 -261.066788)
		(size 0.4572)
		(drill 0.2032)
		(layers "F.Cu" "B.Cu")
		(net "GND")
	)
	(via
		(at 348.882462 -266.128246)
		(size 0.4572)
		(drill 0.2032)
		(layers "F.Cu" "B.Cu")
		(net "GND")
	)
	(via
		(at 348.014036 -410.664152)
		(size 0.4572)
		(drill 0.254)
		(layers "F.Cu" "B.Cu")
		(net "GND")
	)
	(via
		(at 307.782214 -223.666558)
		(size 0.4572)
		(drill 0.2032)
		(layers "F.Cu" "B.Cu")
		(net "GND")
	)
	(via
		(at 427.129448 -126.81966)
		(size 0.508)
		(drill 0.254)
		(layers "F.Cu" "B.Cu")
		(net "GND")
	)
	(via
		(at 136.654794 -285.661354)
		(size 0.4572)
		(drill 0.2032)
		(layers "F.Cu" "B.Cu")
		(net "GND")
	)
	(via
		(at 35.807396 -102.07879)
		(size 0.508)
		(drill 0.254)
		(layers "F.Cu" "B.Cu")
		(net "GND")
	)
	(via
		(at 283.916882 -294.216582)
		(size 0.4572)
		(drill 0.2032)
		(layers "F.Cu" "B.Cu")
		(net "GND")
	)
	(via
		(at 413.349948 -426.54728)
		(size 0.4572)
		(drill 0.2032)
		(layers "F.Cu" "B.Cu")
		(net "GND")
	)
	(via
		(at 54.508146 -258.516628)
		(size 0.4572)
		(drill 0.2032)
		(layers "F.Cu" "B.Cu")
		(net "GND")
	)
	(via
		(at 337.0199 -409.396184)
		(size 0.4572)
		(drill 0.254)
		(layers "F.Cu" "B.Cu")
		(net "GND")
	)
	(via
		(at 405.349964 -436.051198)
		(size 0.4572)
		(drill 0.2032)
		(layers "F.Cu" "B.Cu")
		(net "GND")
	)
	(via
		(at 300.238414 -233.016806)
		(size 0.4572)
		(drill 0.2032)
		(layers "F.Cu" "B.Cu")
		(net "GND")
	)
	(via
		(at 48.854614 -269.566644)
		(size 0.4572)
		(drill 0.2032)
		(layers "F.Cu" "B.Cu")
		(net "GND")
	)
	(via
		(at 110.15853 -54.574948)
		(size 0.508)
		(drill 0.254)
		(layers "F.Cu" "B.Cu")
		(net "GND")
	)
	(via
		(at 135.14705 -14.705076)
		(size 0.508)
		(drill 0.254)
		(layers "F.Cu" "B.Cu")
		(net "GND")
	)
	(via
		(at 136.349994 -438.499758)
		(size 0.4572)
		(drill 0.2032)
		(layers "F.Cu" "B.Cu")
		(net "GND")
	)
	(via
		(at 125.267466 -217.064336)
		(size 0.4572)
		(drill 0.2032)
		(layers "F.Cu" "B.Cu")
		(net "GND")
	)
	(via
		(at 175.233584 -217.716608)
		(size 0.4572)
		(drill 0.2032)
		(layers "F.Cu" "B.Cu")
		(net "GND")
	)
	(via
		(at 285.150814 -210.916774)
		(size 0.4572)
		(drill 0.2032)
		(layers "F.Cu" "B.Cu")
		(net "GND")
	)
	(via
		(at 31.876746 -220.266768)
		(size 0.4572)
		(drill 0.2032)
		(layers "F.Cu" "B.Cu")
		(net "GND")
	)
	(via
		(at 22.123146 -289.11677)
		(size 0.4572)
		(drill 0.2032)
		(layers "F.Cu" "B.Cu")
		(net "GND")
	)
	(via
		(at 127.726948 -265.314176)
		(size 0.4572)
		(drill 0.2032)
		(layers "F.Cu" "B.Cu")
		(net "GND")
	)
	(via
		(at 102.352094 -289.807142)
		(size 0.4572)
		(drill 0.2032)
		(layers "F.Cu" "B.Cu")
		(net "GND")
	)
	(via
		(at 392.543538 -39.63289)
		(size 0.508)
		(drill 0.254)
		(layers "F.Cu" "B.Cu")
		(net "GND")
	)
	(via
		(at 315.250068 -429.147224)
		(size 0.4572)
		(drill 0.2032)
		(layers "F.Cu" "B.Cu")
		(net "GND")
	)
	(via
		(at 92.844366 -229.272846)
		(size 0.4572)
		(drill 0.2032)
		(layers "F.Cu" "B.Cu")
		(net "GND")
	)
	(via
		(at 54.508146 -287.416748)
		(size 0.4572)
		(drill 0.2032)
		(layers "F.Cu" "B.Cu")
		(net "GND")
	)
	(via
		(at 134.207758 -339.339428)
		(size 0.508)
		(drill 0.254)
		(layers "F.Cu" "B.Cu")
		(net "GND")
	)
	(via
		(at 405.410924 -238.966756)
		(size 0.4572)
		(drill 0.2032)
		(layers "F.Cu" "B.Cu")
		(net "GND")
	)
	(via
		(at 187.883546 -283.166566)
		(size 0.4572)
		(drill 0.2032)
		(layers "F.Cu" "B.Cu")
		(net "GND")
	)
	(via
		(at 305.2572 -24.0284)
		(size 0.508)
		(drill 0.254)
		(layers "F.Cu" "B.Cu")
		(net "GND")
	)
	(via
		(at 300.238414 -206.666592)
		(size 0.4572)
		(drill 0.2032)
		(layers "F.Cu" "B.Cu")
		(net "GND")
	)
	(via
		(at 409.748482 -299.316648)
		(size 0.4572)
		(drill 0.2032)
		(layers "F.Cu" "B.Cu")
		(net "GND")
	)
	(via
		(at 293.093902 -359.513124)
		(size 0.508)
		(drill 0.254)
		(layers "F.Cu" "B.Cu")
		(net "GND")
	)
	(via
		(at 345.15171 -50.59172)
		(size 0.4572)
		(drill 0.2032)
		(layers "F.Cu" "B.Cu")
		(net "GND")
	)
	(via
		(at 109.870494 -266.941808)
		(size 0.4572)
		(drill 0.2032)
		(layers "F.Cu" "B.Cu")
		(net "GND")
	)
	(via
		(at 261.285482 -306.96662)
		(size 0.4572)
		(drill 0.2032)
		(layers "F.Cu" "B.Cu")
		(net "GND")
	)
	(via
		(at 448.327272 -20.420838)
		(size 0.508)
		(drill 0.254)
		(layers "F.Cu" "B.Cu")
		(net "GND")
	)
	(via
		(at 159.918146 -296.766742)
		(size 0.4572)
		(drill 0.2032)
		(layers "F.Cu" "B.Cu")
		(net "GND")
	)
	(via
		(at 338.395818 -56.438546)
		(size 0.4572)
		(drill 0.2032)
		(layers "F.Cu" "B.Cu")
		(net "GND")
	)
	(via
		(at 373.291354 -173.987968)
		(size 0.508)
		(drill 0.254)
		(layers "F.Cu" "B.Cu")
		(net "GND")
	)
	(via
		(at 199.527414 -211.766658)
		(size 0.4572)
		(drill 0.2032)
		(layers "F.Cu" "B.Cu")
		(net "GND")
	)
	(via
		(at 138.34999 -431.451258)
		(size 0.4572)
		(drill 0.2032)
		(layers "F.Cu" "B.Cu")
		(net "GND")
	)
	(via
		(at 59.57697 -409.396184)
		(size 0.4572)
		(drill 0.254)
		(layers "F.Cu" "B.Cu")
		(net "GND")
	)
	(via
		(at 26.223214 -262.76681)
		(size 0.4572)
		(drill 0.2032)
		(layers "F.Cu" "B.Cu")
		(net "GND")
	)
	(via
		(at 209.281014 -241.516662)
		(size 0.4572)
		(drill 0.2032)
		(layers "F.Cu" "B.Cu")
		(net "GND")
	)
	(via
		(at 59.842146 -212.616796)
		(size 0.4572)
		(drill 0.2032)
		(layers "F.Cu" "B.Cu")
		(net "GND")
	)
	(via
		(at 335.615534 -226.831144)
		(size 0.4572)
		(drill 0.2032)
		(layers "F.Cu" "B.Cu")
		(net "GND")
	)
	(via
		(at 460.664814 -292.516814)
		(size 0.4572)
		(drill 0.2032)
		(layers "F.Cu" "B.Cu")
		(net "GND")
	)
	(via
		(at 41.310814 -303.566576)
		(size 0.4572)
		(drill 0.2032)
		(layers "F.Cu" "B.Cu")
		(net "GND")
	)
	(via
		(at 428.279814 -298.466764)
		(size 0.4572)
		(drill 0.2032)
		(layers "F.Cu" "B.Cu")
		(net "GND")
	)
	(via
		(at 257.185414 -301.866808)
		(size 0.4572)
		(drill 0.2032)
		(layers "F.Cu" "B.Cu")
		(net "GND")
	)
	(via
		(at 386.350002 -433.899564)
		(size 0.4572)
		(drill 0.2032)
		(layers "F.Cu" "B.Cu")
		(net "GND")
	)
	(via
		(at 13.345414 -280.61666)
		(size 0.4572)
		(drill 0.2032)
		(layers "F.Cu" "B.Cu")
		(net "GND")
	)
	(via
		(at 98.013266 -243.108988)
		(size 0.4572)
		(drill 0.2032)
		(layers "F.Cu" "B.Cu")
		(net "GND")
	)
	(via
		(at 279.816814 -210.916774)
		(size 0.4572)
		(drill 0.2032)
		(layers "F.Cu" "B.Cu")
		(net "GND")
	)
	(via
		(at 334.899508 -46.449996)
		(size 0.4572)
		(drill 0.2032)
		(layers "F.Cu" "B.Cu")
		(net "GND")
	)
	(via
		(at 103.291894 -273.453098)
		(size 0.4572)
		(drill 0.2032)
		(layers "F.Cu" "B.Cu")
		(net "GND")
	)
	(via
		(at 29.666692 -415.366962)
		(size 0.508)
		(drill 0.254)
		(layers "F.Cu" "B.Cu")
		(net "GND")
	)
	(via
		(at 164.018214 -267.866622)
		(size 0.4572)
		(drill 0.2032)
		(layers "F.Cu" "B.Cu")
		(net "GND")
	)
	(via
		(at 51.064414 -262.76681)
		(size 0.4572)
		(drill 0.2032)
		(layers "F.Cu" "B.Cu")
		(net "GND")
	)
	(via
		(at 254.975614 -263.616694)
		(size 0.4572)
		(drill 0.2032)
		(layers "F.Cu" "B.Cu")
		(net "GND")
	)
	(via
		(at 41.884092 -345.64066)
		(size 0.508)
		(drill 0.254)
		(layers "F.Cu" "B.Cu")
		(net "GND")
	)
	(via
		(at 29.666946 -223.666558)
		(size 0.4572)
		(drill 0.2032)
		(layers "F.Cu" "B.Cu")
		(net "GND")
	)
	(via
		(at 279.816814 -300.166786)
		(size 0.4572)
		(drill 0.2032)
		(layers "F.Cu" "B.Cu")
		(net "GND")
	)
	(via
		(at 427.766988 -7.215124)
		(size 0.508)
		(drill 0.254)
		(layers "F.Cu" "B.Cu")
		(net "GND")
	)
	(via
		(at 438.033414 -260.21665)
		(size 0.4572)
		(drill 0.2032)
		(layers "F.Cu" "B.Cu")
		(net "GND")
	)
	(via
		(at 291.460682 -222.816674)
		(size 0.4572)
		(drill 0.2032)
		(layers "F.Cu" "B.Cu")
		(net "GND")
	)
	(via
		(at 424.836082 -301.01667)
		(size 0.4572)
		(drill 0.2032)
		(layers "F.Cu" "B.Cu")
		(net "GND")
	)
	(via
		(at 342.250014 -432.451256)
		(size 0.4572)
		(drill 0.2032)
		(layers "F.Cu" "B.Cu")
		(net "GND")
	)
	(via
		(at 413.408114 -367.740184)
		(size 0.508)
		(drill 0.254)
		(layers "F.Cu" "B.Cu")
		(net "GND")
	)
	(via
		(at 458.3811 -387.30682)
		(size 0.508)
		(drill 0.254)
		(layers "F.Cu" "B.Cu")
		(net "GND")
	)
	(via
		(at 375.667016 -271.825212)
		(size 0.4572)
		(drill 0.2032)
		(layers "F.Cu" "B.Cu")
		(net "GND")
	)
	(via
		(at 409.482798 -312.892948)
		(size 0.4572)
		(drill 0.2032)
		(layers "F.Cu" "B.Cu")
		(net "GND")
	)
	(via
		(at 279.816814 -317.166752)
		(size 0.4572)
		(drill 0.2032)
		(layers "F.Cu" "B.Cu")
		(net "GND")
	)
	(via
		(at 104.46639 -331.776832)
		(size 0.49022)
		(drill 0.254)
		(layers "F.Cu" "B.Cu")
		(net "GND")
	)
	(via
		(at 20.889214 -245.76659)
		(size 0.4572)
		(drill 0.2032)
		(layers "F.Cu" "B.Cu")
		(net "GND")
	)
	(via
		(at 308.108604 -14.412468)
		(size 0.508)
		(drill 0.254)
		(layers "F.Cu" "B.Cu")
		(net "GND")
	)
	(via
		(at 254.975614 -227.066602)
		(size 0.4572)
		(drill 0.2032)
		(layers "F.Cu" "B.Cu")
		(net "GND")
	)
	(via
		(at 450.911214 -220.266768)
		(size 0.4572)
		(drill 0.2032)
		(layers "F.Cu" "B.Cu")
		(net "GND")
	)
	(via
		(at 354.7364 -404.876)
		(size 0.508)
		(drill 0.254)
		(layers "F.Cu" "B.Cu")
		(net "GND")
	)
	(via
		(at 254.975614 -304.416714)
		(size 0.4572)
		(drill 0.2032)
		(layers "F.Cu" "B.Cu")
		(net "GND")
	)
	(via
		(at 348.302834 -227.64496)
		(size 0.4572)
		(drill 0.2032)
		(layers "F.Cu" "B.Cu")
		(net "GND")
	)
	(via
		(at 412.92907 -220.266768)
		(size 0.4572)
		(drill 0.2032)
		(layers "F.Cu" "B.Cu")
		(net "GND")
	)
	(via
		(at 372.571518 -410.664152)
		(size 0.4572)
		(drill 0.254)
		(layers "F.Cu" "B.Cu")
		(net "GND")
	)
	(via
		(at 344.673682 -338.86013)
		(size 0.508)
		(drill 0.254)
		(layers "F.Cu" "B.Cu")
		(net "GND")
	)
	(via
		(at 91.074748 -258.80314)
		(size 0.4572)
		(drill 0.2032)
		(layers "F.Cu" "B.Cu")
		(net "GND")
	)
	(via
		(at 175.005746 -210.916774)
		(size 0.4572)
		(drill 0.2032)
		(layers "F.Cu" "B.Cu")
		(net "GND")
	)
	(via
		(at 132.350002 -432.451256)
		(size 0.4572)
		(drill 0.2032)
		(layers "F.Cu" "B.Cu")
		(net "GND")
	)
	(via
		(at 238.30788 -421.909748)
		(size 0.508)
		(drill 0.254)
		(layers "F.Cu" "B.Cu")
		(net "GND")
	)
	(via
		(at 122.917966 -216.25052)
		(size 0.4572)
		(drill 0.2032)
		(layers "F.Cu" "B.Cu")
		(net "GND")
	)
	(via
		(at 453.121014 -300.166786)
		(size 0.4572)
		(drill 0.2032)
		(layers "F.Cu" "B.Cu")
		(net "GND")
	)
	(via
		(at 400.498056 -4.95173)
		(size 0.508)
		(drill 0.254)
		(layers "F.Cu" "B.Cu")
		(net "GND")
	)
	(via
		(at 23.69693 -193.552826)
		(size 0.508)
		(drill 0.254)
		(layers "F.Cu" "B.Cu")
		(net "GND")
	)
	(via
		(at 56.398414 -271.266666)
		(size 0.4572)
		(drill 0.2032)
		(layers "F.Cu" "B.Cu")
		(net "GND")
	)
	(via
		(at 52.191666 -409.396184)
		(size 0.4572)
		(drill 0.254)
		(layers "F.Cu" "B.Cu")
		(net "GND")
	)
	(via
		(at 167.164766 -401.492212)
		(size 0.4572)
		(drill 0.254)
		(layers "F.Cu" "B.Cu")
		(net "GND")
	)
	(via
		(at 464.53552 -428.39513)
		(size 0.508)
		(drill 0.254)
		(layers "F.Cu" "B.Cu")
		(net "GND")
	)
	(via
		(at 283.916882 -278.916638)
		(size 0.4572)
		(drill 0.2032)
		(layers "F.Cu" "B.Cu")
		(net "GND")
	)
	(via
		(at 138.336782 -400.200368)
		(size 0.4572)
		(drill 0.254)
		(layers "F.Cu" "B.Cu")
		(net "GND")
	)
	(via
		(at 462.555082 -211.766658)
		(size 0.4572)
		(drill 0.2032)
		(layers "F.Cu" "B.Cu")
		(net "GND")
	)
	(via
		(at 382.135634 -232.528364)
		(size 0.4572)
		(drill 0.2032)
		(layers "F.Cu" "B.Cu")
		(net "GND")
	)
	(via
		(at 413.818324 -156.610304)
		(size 0.508)
		(drill 0.254)
		(layers "F.Cu" "B.Cu")
		(net "GND")
	)
	(via
		(at 434.589682 -288.266632)
		(size 0.4572)
		(drill 0.2032)
		(layers "F.Cu" "B.Cu")
		(net "GND")
	)
	(via
		(at 48.902366 -439.152538)
		(size 0.508)
		(drill 0.254)
		(layers "F.Cu" "B.Cu")
		(net "GND")
	)
	(via
		(at 127.147066 -220.319854)
		(size 0.4572)
		(drill 0.2032)
		(layers "F.Cu" "B.Cu")
		(net "GND")
	)
	(via
		(at 384.387852 -340.977728)
		(size 0.49022)
		(drill 0.254)
		(layers "F.Cu" "B.Cu")
		(net "GND")
	)
	(via
		(at 266.619482 -295.916604)
		(size 0.4572)
		(drill 0.2032)
		(layers "F.Cu" "B.Cu")
		(net "GND")
	)
	(via
		(at 270.063214 -263.616694)
		(size 0.4572)
		(drill 0.2032)
		(layers "F.Cu" "B.Cu")
		(net "GND")
	)
	(via
		(at 56.83885 -157.919674)
		(size 0.49022)
		(drill 0.254)
		(layers "F.Cu" "B.Cu")
		(net "GND")
	)
	(via
		(at 334.67548 -217.064336)
		(size 0.4572)
		(drill 0.2032)
		(layers "F.Cu" "B.Cu")
		(net "GND")
	)
	(via
		(at 84.495894 -255.547622)
		(size 0.4572)
		(drill 0.2032)
		(layers "F.Cu" "B.Cu")
		(net "GND")
	)
	(via
		(at 45.890688 -350.567498)
		(size 0.508)
		(drill 0.254)
		(layers "F.Cu" "B.Cu")
		(net "GND")
	)
	(via
		(at 296.794682 -282.316682)
		(size 0.4572)
		(drill 0.2032)
		(layers "F.Cu" "B.Cu")
		(net "GND")
	)
	(via
		(at 16.789146 -267.016738)
		(size 0.4572)
		(drill 0.2032)
		(layers "F.Cu" "B.Cu")
		(net "GND")
	)
	(via
		(at 364.279434 -229.272846)
		(size 0.4572)
		(drill 0.2032)
		(layers "F.Cu" "B.Cu")
		(net "GND")
	)
	(via
		(at 371.225318 -400.224244)
		(size 0.4572)
		(drill 0.254)
		(layers "F.Cu" "B.Cu")
		(net "GND")
	)
	(via
		(at 450.911214 -276.366732)
		(size 0.4572)
		(drill 0.2032)
		(layers "F.Cu" "B.Cu")
		(net "GND")
	)
	(via
		(at 361.008676 -338.86013)
		(size 0.508)
		(drill 0.254)
		(layers "F.Cu" "B.Cu")
		(net "GND")
	)
	(via
		(at 149.146514 -403.883876)
		(size 0.4064)
		(drill 0.2032)
		(layers "F.Cu" "B.Cu")
		(net "GND")
	)
	(via
		(at 87.573104 -37.709348)
		(size 0.508)
		(drill 0.254)
		(layers "F.Cu" "B.Cu")
		(net "GND")
	)
	(via
		(at 453.121014 -240.666778)
		(size 0.4572)
		(drill 0.2032)
		(layers "F.Cu" "B.Cu")
		(net "GND")
	)
	(via
		(at 383.075434 -247.178322)
		(size 0.4572)
		(drill 0.2032)
		(layers "F.Cu" "B.Cu")
		(net "GND")
	)
	(via
		(at 135.14705 -17.655032)
		(size 0.508)
		(drill 0.254)
		(layers "F.Cu" "B.Cu")
		(net "GND")
	)
	(via
		(at 302.505364 -319.712594)
		(size 0.4572)
		(drill 0.2032)
		(layers "F.Cu" "B.Cu")
		(net "GND")
	)
	(via
		(at 261.285482 -278.916638)
		(size 0.4572)
		(drill 0.2032)
		(layers "F.Cu" "B.Cu")
		(net "GND")
	)
	(via
		(at 63.001398 -410.030168)
		(size 0.4064)
		(drill 0.2032)
		(layers "F.Cu" "B.Cu")
		(net "GND")
	)
	(via
		(at 9.245346 -292.516814)
		(size 0.4572)
		(drill 0.2032)
		(layers "F.Cu" "B.Cu")
		(net "GND")
	)
	(via
		(at 447.467482 -230.466646)
		(size 0.4572)
		(drill 0.2032)
		(layers "F.Cu" "B.Cu")
		(net "GND")
	)
	(via
		(at 349.731076 -404.51786)
		(size 0.4572)
		(drill 0.254)
		(layers "F.Cu" "B.Cu")
		(net "GND")
	)
	(via
		(at 214.68588 -54.999128)
		(size 0.508)
		(drill 0.254)
		(layers "F.Cu" "B.Cu")
		(net "GND")
	)
	(via
		(at 387.568694 -244.458744)
		(size 0.4572)
		(drill 0.2032)
		(layers "F.Cu" "B.Cu")
		(net "GND")
	)
	(via
		(at 28.433014 -272.966688)
		(size 0.4572)
		(drill 0.2032)
		(layers "F.Cu" "B.Cu")
		(net "GND")
	)
	(via
		(at 65.25006 -439.651394)
		(size 0.4572)
		(drill 0.2032)
		(layers "F.Cu" "B.Cu")
		(net "GND")
	)
	(via
		(at 47.782226 -400.224244)
		(size 0.4572)
		(drill 0.254)
		(layers "F.Cu" "B.Cu")
		(net "GND")
	)
	(via
		(at 44.754546 -234.716574)
		(size 0.4572)
		(drill 0.2032)
		(layers "F.Cu" "B.Cu")
		(net "GND")
	)
	(via
		(at 395.62024 -50.015648)
		(size 0.508)
		(drill 0.254)
		(layers "F.Cu" "B.Cu")
		(net "GND")
	)
	(via
		(at 338.73694 -401.492212)
		(size 0.4572)
		(drill 0.254)
		(layers "F.Cu" "B.Cu")
		(net "GND")
	)
	(via
		(at 35.976814 -301.01667)
		(size 0.4572)
		(drill 0.2032)
		(layers "F.Cu" "B.Cu")
		(net "GND")
	)
	(via
		(at 290.967668 -362.422694)
		(size 0.49022)
		(drill 0.254)
		(layers "F.Cu" "B.Cu")
		(net "GND")
	)
	(via
		(at 209.281014 -228.766624)
		(size 0.4572)
		(drill 0.2032)
		(layers "F.Cu" "B.Cu")
		(net "GND")
	)
	(via
		(at 353.001834 -219.506038)
		(size 0.4572)
		(drill 0.2032)
		(layers "F.Cu" "B.Cu")
		(net "GND")
	)
	(via
		(at 453.121014 -214.316564)
		(size 0.4572)
		(drill 0.2032)
		(layers "F.Cu" "B.Cu")
		(net "GND")
	)
	(via
		(at 359.110534 -228.45903)
		(size 0.4572)
		(drill 0.2032)
		(layers "F.Cu" "B.Cu")
		(net "GND")
	)
	(via
		(at 302.448214 -279.766776)
		(size 0.4572)
		(drill 0.2032)
		(layers "F.Cu" "B.Cu")
		(net "GND")
	)
	(via
		(at 415.402014 -298.466764)
		(size 0.4572)
		(drill 0.2032)
		(layers "F.Cu" "B.Cu")
		(net "GND")
	)
	(via
		(at 111.170212 -225.203258)
		(size 0.4572)
		(drill 0.2032)
		(layers "F.Cu" "B.Cu")
		(net "GND")
	)
	(via
		(at 46.964346 -298.466764)
		(size 0.4572)
		(drill 0.2032)
		(layers "F.Cu" "B.Cu")
		(net "GND")
	)
	(via
		(at 34.894266 -18.502376)
		(size 0.508)
		(drill 0.254)
		(layers "F.Cu" "B.Cu")
		(net "GND")
	)
	(via
		(at 230.156258 -126.071122)
		(size 0.508)
		(drill 0.254)
		(layers "F.Cu" "B.Cu")
		(net "GND")
	)
	(via
		(at 382.366012 -57.277508)
		(size 0.508)
		(drill 0.254)
		(layers "F.Cu" "B.Cu")
		(net "GND")
	)
	(via
		(at 458.455014 -240.666778)
		(size 0.4572)
		(drill 0.2032)
		(layers "F.Cu" "B.Cu")
		(net "GND")
	)
	(via
		(at 79.67345 -403.249892)
		(size 0.4572)
		(drill 0.254)
		(layers "F.Cu" "B.Cu")
		(net "GND")
	)
	(via
		(at 437.70296 -47.0408)
		(size 0.508)
		(drill 0.254)
		(layers "F.Cu" "B.Cu")
		(net "GND")
	)
	(via
		(at 101.302566 -245.55069)
		(size 0.4572)
		(drill 0.2032)
		(layers "F.Cu" "B.Cu")
		(net "GND")
	)
	(via
		(at 427.045882 -277.216616)
		(size 0.4572)
		(drill 0.2032)
		(layers "F.Cu" "B.Cu")
		(net "GND")
	)
	(via
		(at 363.809534 -213.732618)
		(size 0.4572)
		(drill 0.2032)
		(layers "F.Cu" "B.Cu")
		(net "GND")
	)
	(via
		(at 94.253812 -228.45903)
		(size 0.4572)
		(drill 0.2032)
		(layers "F.Cu" "B.Cu")
		(net "GND")
	)
	(via
		(at 164.033454 -215.166702)
		(size 0.4572)
		(drill 0.2032)
		(layers "F.Cu" "B.Cu")
		(net "GND")
	)
	(via
		(at 325.199248 -346.885006)
		(size 0.508)
		(drill 0.254)
		(layers "F.Cu" "B.Cu")
		(net "GND")
	)
	(via
		(at 420.736014 -214.316564)
		(size 0.4572)
		(drill 0.2032)
		(layers "F.Cu" "B.Cu")
		(net "GND")
	)
	(via
		(at 442.133482 -207.51673)
		(size 0.4572)
		(drill 0.2032)
		(layers "F.Cu" "B.Cu")
		(net "GND")
	)
	(via
		(at 429.566832 -10.16508)
		(size 0.508)
		(drill 0.254)
		(layers "F.Cu" "B.Cu")
		(net "GND")
	)
	(via
		(at 259.075682 -202.416664)
		(size 0.4572)
		(drill 0.2032)
		(layers "F.Cu" "B.Cu")
		(net "GND")
	)
	(via
		(at 259.075682 -277.216616)
		(size 0.4572)
		(drill 0.2032)
		(layers "F.Cu" "B.Cu")
		(net "GND")
	)
	(via
		(at 380.835662 -256.361438)
		(size 0.4572)
		(drill 0.2032)
		(layers "F.Cu" "B.Cu")
		(net "GND")
	)
	(via
		(at 40.923972 -353.187)
		(size 0.49022)
		(drill 0.254)
		(layers "F.Cu" "B.Cu")
		(net "GND")
	)
	(via
		(at 61.250068 -427.699678)
		(size 0.4572)
		(drill 0.2032)
		(layers "F.Cu" "B.Cu")
		(net "GND")
	)
	(via
		(at 335.138268 -56.438546)
		(size 0.4572)
		(drill 0.2032)
		(layers "F.Cu" "B.Cu")
		(net "GND")
	)
	(via
		(at 90.25001 -434.899562)
		(size 0.4572)
		(drill 0.2032)
		(layers "F.Cu" "B.Cu")
		(net "GND")
	)
	(via
		(at 289.250882 -267.866622)
		(size 0.4572)
		(drill 0.2032)
		(layers "F.Cu" "B.Cu")
		(net "GND")
	)
	(via
		(at 261.285482 -314.616592)
		(size 0.4572)
		(drill 0.2032)
		(layers "F.Cu" "B.Cu")
		(net "GND")
	)
	(via
		(at 58.608214 -200.716642)
		(size 0.4572)
		(drill 0.2032)
		(layers "F.Cu" "B.Cu")
		(net "GND")
	)
	(via
		(at 415.456878 -409.396184)
		(size 0.4572)
		(drill 0.254)
		(layers "F.Cu" "B.Cu")
		(net "GND")
	)
	(via
		(at 117.397784 -295.03878)
		(size 0.508)
		(drill 0.254)
		(layers "F.Cu" "B.Cu")
		(net "GND")
	)
	(via
		(at 321.7037 -409.396184)
		(size 0.4572)
		(drill 0.254)
		(layers "F.Cu" "B.Cu")
		(net "GND")
	)
	(via
		(at 383.020062 -406.370536)
		(size 0.4572)
		(drill 0.254)
		(layers "F.Cu" "B.Cu")
		(net "GND")
	)
	(via
		(at 445.577214 -304.416714)
		(size 0.4572)
		(drill 0.2032)
		(layers "F.Cu" "B.Cu")
		(net "GND")
	)
	(via
		(at 279.816814 -225.36658)
		(size 0.4572)
		(drill 0.2032)
		(layers "F.Cu" "B.Cu")
		(net "GND")
	)
	(via
		(at 7.035546 -315.46673)
		(size 0.4572)
		(drill 0.2032)
		(layers "F.Cu" "B.Cu")
		(net "GND")
	)
	(via
		(at 302.448214 -306.116736)
		(size 0.4572)
		(drill 0.2032)
		(layers "F.Cu" "B.Cu")
		(net "GND")
	)
	(via
		(at 136.184894 -283.219906)
		(size 0.4572)
		(drill 0.2032)
		(layers "F.Cu" "B.Cu")
		(net "GND")
	)
	(via
		(at 209.57413 -12.544552)
		(size 0.508)
		(drill 0.254)
		(layers "F.Cu" "B.Cu")
		(net "GND")
	)
	(via
		(at 382.245616 -253.919736)
		(size 0.4572)
		(drill 0.2032)
		(layers "F.Cu" "B.Cu")
		(net "GND")
	)
	(via
		(at 120.94972 -240.12017)
		(size 0.4572)
		(drill 0.2032)
		(layers "F.Cu" "B.Cu")
		(net "GND")
	)
	(via
		(at 157.708346 -301.866808)
		(size 0.4572)
		(drill 0.2032)
		(layers "F.Cu" "B.Cu")
		(net "GND")
	)
	(via
		(at 424.836082 -216.866724)
		(size 0.4572)
		(drill 0.2032)
		(layers "F.Cu" "B.Cu")
		(net "GND")
	)
	(via
		(at 199.527414 -249.166634)
		(size 0.4572)
		(drill 0.2032)
		(layers "F.Cu" "B.Cu")
		(net "GND")
	)
	(via
		(at 338.904834 -243.922804)
		(size 0.4572)
		(drill 0.2032)
		(layers "F.Cu" "B.Cu")
		(net "GND")
	)
	(via
		(at 458.455014 -298.466764)
		(size 0.4572)
		(drill 0.2032)
		(layers "F.Cu" "B.Cu")
		(net "GND")
	)
	(via
		(at 120.97639 -257.283204)
		(size 0.4572)
		(drill 0.2032)
		(layers "F.Cu" "B.Cu")
		(net "GND")
	)
	(via
		(at 368.916204 -252.60935)
		(size 0.4572)
		(drill 0.2032)
		(layers "F.Cu" "B.Cu")
		(net "GND")
	)
	(via
		(at 272.273014 -311.216802)
		(size 0.4572)
		(drill 0.2032)
		(layers "F.Cu" "B.Cu")
		(net "GND")
	)
	(via
		(at 127.430022 -406.370536)
		(size 0.4572)
		(drill 0.254)
		(layers "F.Cu" "B.Cu")
		(net "GND")
	)
	(via
		(at 41.310814 -222.816674)
		(size 0.4572)
		(drill 0.2032)
		(layers "F.Cu" "B.Cu")
		(net "GND")
	)
	(via
		(at 254.975614 -295.06672)
		(size 0.4572)
		(drill 0.2032)
		(layers "F.Cu" "B.Cu")
		(net "GND")
	)
	(via
		(at 96.697038 -410.030168)
		(size 0.4064)
		(drill 0.2032)
		(layers "F.Cu" "B.Cu")
		(net "GND")
	)
	(via
		(at 207.071214 -266.1666)
		(size 0.4572)
		(drill 0.2032)
		(layers "F.Cu" "B.Cu")
		(net "GND")
	)
	(via
		(at 125.847094 -257.175254)
		(size 0.4572)
		(drill 0.2032)
		(layers "F.Cu" "B.Cu")
		(net "GND")
	)
	(via
		(at 10.873486 -91.658948)
		(size 0.508)
		(drill 0.254)
		(layers "F.Cu" "B.Cu")
		(net "GND")
	)
	(via
		(at 270.063214 -203.266802)
		(size 0.4572)
		(drill 0.2032)
		(layers "F.Cu" "B.Cu")
		(net "GND")
	)
	(via
		(at 288.754566 -360.83621)
		(size 0.49022)
		(drill 0.254)
		(layers "F.Cu" "B.Cu")
		(net "GND")
	)
	(via
		(at 29.666946 -250.016772)
		(size 0.4572)
		(drill 0.2032)
		(layers "F.Cu" "B.Cu")
		(net "GND")
	)
	(via
		(at 325.15429 -339.700108)
		(size 0.508)
		(drill 0.254)
		(layers "F.Cu" "B.Cu")
		(net "GND")
	)
	(via
		(at 94.723966 -226.017328)
		(size 0.4572)
		(drill 0.2032)
		(layers "F.Cu" "B.Cu")
		(net "GND")
	)
	(via
		(at 384.350006 -434.899562)
		(size 0.4572)
		(drill 0.2032)
		(layers "F.Cu" "B.Cu")
		(net "GND")
	)
	(via
		(at 319.426844 -339.000846)
		(size 0.508)
		(drill 0.254)
		(layers "F.Cu" "B.Cu")
		(net "GND")
	)
	(via
		(at 117.53088 -102.809548)
		(size 0.508)
		(drill 0.254)
		(layers "F.Cu" "B.Cu")
		(net "GND")
	)
	(via
		(at 48.638714 -219.41663)
		(size 0.4572)
		(drill 0.2032)
		(layers "F.Cu" "B.Cu")
		(net "GND")
	)
	(via
		(at 91.074494 -271.825212)
		(size 0.4572)
		(drill 0.2032)
		(layers "F.Cu" "B.Cu")
		(net "GND")
	)
	(via
		(at 54.508146 -201.56678)
		(size 0.4572)
		(drill 0.2032)
		(layers "F.Cu" "B.Cu")
		(net "GND")
	)
	(via
		(at 201.737214 -277.216616)
		(size 0.4572)
		(drill 0.2032)
		(layers "F.Cu" "B.Cu")
		(net "GND")
	)
	(via
		(at 51.064414 -221.116652)
		(size 0.4572)
		(drill 0.2032)
		(layers "F.Cu" "B.Cu")
		(net "GND")
	)
	(via
		(at 415.402014 -279.766776)
		(size 0.4572)
		(drill 0.2032)
		(layers "F.Cu" "B.Cu")
		(net "GND")
	)
	(via
		(at 386.350002 -438.651396)
		(size 0.4572)
		(drill 0.2032)
		(layers "F.Cu" "B.Cu")
		(net "GND")
	)
	(via
		(at 415.402014 -263.616694)
		(size 0.4572)
		(drill 0.2032)
		(layers "F.Cu" "B.Cu")
		(net "GND")
	)
	(via
		(at 370.967762 -289.807142)
		(size 0.4572)
		(drill 0.2032)
		(layers "F.Cu" "B.Cu")
		(net "GND")
	)
	(via
		(at 372.60276 -58.489088)
		(size 0.508)
		(drill 0.254)
		(layers "F.Cu" "B.Cu")
		(net "GND")
	)
	(via
		(at 136.075166 -239.0394)
		(size 0.4572)
		(drill 0.2032)
		(layers "F.Cu" "B.Cu")
		(net "GND")
	)
	(via
		(at 375.557034 -235.783882)
		(size 0.4572)
		(drill 0.2032)
		(layers "F.Cu" "B.Cu")
		(net "GND")
	)
	(via
		(at 248.943368 -107.007406)
		(size 0.508)
		(drill 0.254)
		(layers "F.Cu" "B.Cu")
		(net "GND")
	)
	(via
		(at 131.375912 -247.178322)
		(size 0.4572)
		(drill 0.2032)
		(layers "F.Cu" "B.Cu")
		(net "GND")
	)
	(via
		(at 139.321794 -407.00452)
		(size 0.4064)
		(drill 0.2032)
		(layers "F.Cu" "B.Cu")
		(net "GND")
	)
	(via
		(at 84.965794 -264.50036)
		(size 0.4572)
		(drill 0.2032)
		(layers "F.Cu" "B.Cu")
		(net "GND")
	)
	(via
		(at 29.666946 -278.066754)
		(size 0.4572)
		(drill 0.2032)
		(layers "F.Cu" "B.Cu")
		(net "GND")
	)
	(via
		(at 69.250052 -438.499758)
		(size 0.4572)
		(drill 0.2032)
		(layers "F.Cu" "B.Cu")
		(net "GND")
	)
	(via
		(at 356.761034 -229.272846)
		(size 0.4572)
		(drill 0.2032)
		(layers "F.Cu" "B.Cu")
		(net "GND")
	)
	(via
		(at 197.637146 -238.966756)
		(size 0.4572)
		(drill 0.2032)
		(layers "F.Cu" "B.Cu")
		(net "GND")
	)
	(via
		(at 43.520614 -297.616626)
		(size 0.4572)
		(drill 0.2032)
		(layers "F.Cu" "B.Cu")
		(net "GND")
	)
	(via
		(at 79.984854 -341.766906)
		(size 0.49022)
		(drill 0.254)
		(layers "F.Cu" "B.Cu")
		(net "GND")
	)
	(via
		(at 191.983614 -284.866588)
		(size 0.4572)
		(drill 0.2032)
		(layers "F.Cu" "B.Cu")
		(net "GND")
	)
	(via
		(at 62.051946 -309.51678)
		(size 0.4572)
		(drill 0.2032)
		(layers "F.Cu" "B.Cu")
		(net "GND")
	)
	(via
		(at 330.315316 -24.206708)
		(size 0.508)
		(drill 0.254)
		(layers "F.Cu" "B.Cu")
		(net "GND")
	)
	(via
		(at 172.795946 -261.916672)
		(size 0.4572)
		(drill 0.2032)
		(layers "F.Cu" "B.Cu")
		(net "GND")
	)
	(via
		(at 458.455014 -267.016738)
		(size 0.4572)
		(drill 0.2032)
		(layers "F.Cu" "B.Cu")
		(net "GND")
	)
	(via
		(at 341.887556 -406.370536)
		(size 0.4572)
		(drill 0.254)
		(layers "F.Cu" "B.Cu")
		(net "GND")
	)
	(via
		(at 302.448214 -229.616762)
		(size 0.4572)
		(drill 0.2032)
		(layers "F.Cu" "B.Cu")
		(net "GND")
	)
	(via
		(at 366.738916 -285.661354)
		(size 0.4572)
		(drill 0.2032)
		(layers "F.Cu" "B.Cu")
		(net "GND")
	)
	(via
		(at 240.968022 -129.412238)
		(size 0.508)
		(drill 0.254)
		(layers "F.Cu" "B.Cu")
		(net "GND")
	)
	(via
		(at 309.992014 -298.466764)
		(size 0.4572)
		(drill 0.2032)
		(layers "F.Cu" "B.Cu")
		(net "GND")
	)
	(via
		(at 262.519414 -290.816792)
		(size 0.4572)
		(drill 0.2032)
		(layers "F.Cu" "B.Cu")
		(net "GND")
	)
	(via
		(at 343.549478 -41.871392)
		(size 0.4572)
		(drill 0.2032)
		(layers "F.Cu" "B.Cu")
		(net "GND")
	)
	(via
		(at 393.046966 -9.424924)
		(size 0.508)
		(drill 0.254)
		(layers "F.Cu" "B.Cu")
		(net "GND")
	)
	(via
		(at 190.093346 -251.716794)
		(size 0.4572)
		(drill 0.2032)
		(layers "F.Cu" "B.Cu")
		(net "GND")
	)
	(via
		(at 464.764882 -286.56661)
		(size 0.4572)
		(drill 0.2032)
		(layers "F.Cu" "B.Cu")
		(net "GND")
	)
	(via
		(at 254.975614 -307.816758)
		(size 0.4572)
		(drill 0.2032)
		(layers "F.Cu" "B.Cu")
		(net "GND")
	)
	(via
		(at 375.833132 -356.970838)
		(size 0.508)
		(drill 0.254)
		(layers "F.Cu" "B.Cu")
		(net "GND")
	)
	(via
		(at 395.273022 -409.396184)
		(size 0.4572)
		(drill 0.254)
		(layers "F.Cu" "B.Cu")
		(net "GND")
	)
	(via
		(at 422.945814 -263.616694)
		(size 0.4572)
		(drill 0.2032)
		(layers "F.Cu" "B.Cu")
		(net "GND")
	)
	(via
		(at 357.810562 -276.708616)
		(size 0.4572)
		(drill 0.2032)
		(layers "F.Cu" "B.Cu")
		(net "GND")
	)
	(via
		(at 54.333648 -154.97175)
		(size 0.49022)
		(drill 0.254)
		(layers "F.Cu" "B.Cu")
		(net "GND")
	)
	(via
		(at 254.975614 -278.066754)
		(size 0.4572)
		(drill 0.2032)
		(layers "F.Cu" "B.Cu")
		(net "GND")
	)
	(via
		(at 377.03633 -365.657892)
		(size 0.508)
		(drill 0.254)
		(layers "F.Cu" "B.Cu")
		(net "GND")
	)
	(via
		(at 274.163282 -269.566644)
		(size 0.4572)
		(drill 0.2032)
		(layers "F.Cu" "B.Cu")
		(net "GND")
	)
	(via
		(at 261.285482 -228.766624)
		(size 0.4572)
		(drill 0.2032)
		(layers "F.Cu" "B.Cu")
		(net "GND")
	)
	(via
		(at 327.83018 -406.370536)
		(size 0.4572)
		(drill 0.254)
		(layers "F.Cu" "B.Cu")
		(net "GND")
	)
	(via
		(at 439.923682 -230.466646)
		(size 0.4572)
		(drill 0.2032)
		(layers "F.Cu" "B.Cu")
		(net "GND")
	)
	(via
		(at 39.10711 -179.531264)
		(size 0.508)
		(drill 0.254)
		(layers "F.Cu" "B.Cu")
		(net "GND")
	)
	(via
		(at 56.398414 -249.166634)
		(size 0.4572)
		(drill 0.2032)
		(layers "F.Cu" "B.Cu")
		(net "GND")
	)
	(via
		(at 136.654794 -277.522432)
		(size 0.4572)
		(drill 0.2032)
		(layers "F.Cu" "B.Cu")
		(net "GND")
	)
	(via
		(at 117.998494 -239.306608)
		(size 0.4572)
		(drill 0.2032)
		(layers "F.Cu" "B.Cu")
		(net "GND")
	)
	(via
		(at 207.071214 -288.266632)
		(size 0.4572)
		(drill 0.2032)
		(layers "F.Cu" "B.Cu")
		(net "GND")
	)
	(via
		(at 126.862332 -342.764872)
		(size 0.508)
		(drill 0.254)
		(layers "F.Cu" "B.Cu")
		(net "GND")
	)
	(via
		(at 78.250034 -426.54728)
		(size 0.4572)
		(drill 0.2032)
		(layers "F.Cu" "B.Cu")
		(net "GND")
	)
	(via
		(at 387.929628 -341.77097)
		(size 0.49022)
		(drill 0.254)
		(layers "F.Cu" "B.Cu")
		(net "GND")
	)
	(via
		(at 50.38725 -406.370536)
		(size 0.4572)
		(drill 0.254)
		(layers "F.Cu" "B.Cu")
		(net "GND")
	)
	(via
		(at 442.133482 -266.1666)
		(size 0.4572)
		(drill 0.2032)
		(layers "F.Cu" "B.Cu")
		(net "GND")
	)
	(via
		(at 420.736014 -290.816792)
		(size 0.4572)
		(drill 0.2032)
		(layers "F.Cu" "B.Cu")
		(net "GND")
	)
	(via
		(at 409.330398 -410.664152)
		(size 0.4572)
		(drill 0.254)
		(layers "F.Cu" "B.Cu")
		(net "GND")
	)
	(via
		(at 259.075682 -213.46668)
		(size 0.4572)
		(drill 0.2032)
		(layers "F.Cu" "B.Cu")
		(net "GND")
	)
	(via
		(at 190.093346 -263.616694)
		(size 0.4572)
		(drill 0.2032)
		(layers "F.Cu" "B.Cu")
		(net "GND")
	)
	(via
		(at 99.40798 -361.894628)
		(size 0.508)
		(drill 0.254)
		(layers "F.Cu" "B.Cu")
		(net "GND")
	)
	(via
		(at 392.30681 -403.883876)
		(size 0.4064)
		(drill 0.2032)
		(layers "F.Cu" "B.Cu")
		(net "GND")
	)
	(via
		(at 296.461688 -361.625388)
		(size 0.49022)
		(drill 0.254)
		(layers "F.Cu" "B.Cu")
		(net "GND")
	)
	(via
		(at 445.577214 -250.016772)
		(size 0.4572)
		(drill 0.2032)
		(layers "F.Cu" "B.Cu")
		(net "GND")
	)
	(via
		(at 198.20636 -119.121428)
		(size 0.508)
		(drill 0.254)
		(layers "F.Cu" "B.Cu")
		(net "GND")
	)
	(via
		(at 332.250034 -432.747166)
		(size 0.4572)
		(drill 0.2032)
		(layers "F.Cu" "B.Cu")
		(net "GND")
	)
	(via
		(at 84.856066 -247.992138)
		(size 0.4572)
		(drill 0.2032)
		(layers "F.Cu" "B.Cu")
		(net "GND")
	)
	(via
		(at 118.218966 -229.272846)
		(size 0.4572)
		(drill 0.2032)
		(layers "F.Cu" "B.Cu")
		(net "GND")
	)
	(via
		(at 100.832666 -213.732618)
		(size 0.4572)
		(drill 0.2032)
		(layers "F.Cu" "B.Cu")
		(net "GND")
	)
	(via
		(at 407.858214 -244.916706)
		(size 0.4572)
		(drill 0.2032)
		(layers "F.Cu" "B.Cu")
		(net "GND")
	)
	(via
		(at 159.918146 -292.516814)
		(size 0.4572)
		(drill 0.2032)
		(layers "F.Cu" "B.Cu")
		(net "GND")
	)
	(via
		(at 59.385962 -160.22828)
		(size 0.508)
		(drill 0.254)
		(layers "F.Cu" "B.Cu")
		(net "GND")
	)
	(via
		(at 285.150814 -279.766776)
		(size 0.4572)
		(drill 0.2032)
		(layers "F.Cu" "B.Cu")
		(net "GND")
	)
	(via
		(at 414.16478 -167.731948)
		(size 0.508)
		(drill 0.254)
		(layers "F.Cu" "B.Cu")
		(net "GND")
	)
	(via
		(at 88.615266 -220.319854)
		(size 0.4572)
		(drill 0.2032)
		(layers "F.Cu" "B.Cu")
		(net "GND")
	)
	(via
		(at 38.13937 -175.464978)
		(size 0.508)
		(drill 0.254)
		(layers "F.Cu" "B.Cu")
		(net "GND")
	)
	(via
		(at 102.895654 -252.214634)
		(size 0.4572)
		(drill 0.2032)
		(layers "F.Cu" "B.Cu")
		(net "GND")
	)
	(via
		(at 64.444626 -406.370536)
		(size 0.4572)
		(drill 0.254)
		(layers "F.Cu" "B.Cu")
		(net "GND")
	)
	(via
		(at 422.945814 -223.666558)
		(size 0.4572)
		(drill 0.2032)
		(layers "F.Cu" "B.Cu")
		(net "GND")
	)
	(via
		(at 41.310814 -271.266666)
		(size 0.4572)
		(drill 0.2032)
		(layers "F.Cu" "B.Cu")
		(net "GND")
	)
	(via
		(at 122.303286 -326.859392)
		(size 0.508)
		(drill 0.254)
		(layers "F.Cu" "B.Cu")
		(net "GND")
	)
	(via
		(at 349.24238 -243.922804)
		(size 0.4572)
		(drill 0.2032)
		(layers "F.Cu" "B.Cu")
		(net "GND")
	)
	(via
		(at 442.133482 -291.666676)
		(size 0.4572)
		(drill 0.2032)
		(layers "F.Cu" "B.Cu")
		(net "GND")
	)
	(via
		(at 342.250014 -439.651394)
		(size 0.4572)
		(drill 0.2032)
		(layers "F.Cu" "B.Cu")
		(net "GND")
	)
	(via
		(at 332.250034 -426.69968)
		(size 0.4572)
		(drill 0.2032)
		(layers "F.Cu" "B.Cu")
		(net "GND")
	)
	(via
		(at 182.549546 -233.016806)
		(size 0.4572)
		(drill 0.2032)
		(layers "F.Cu" "B.Cu")
		(net "GND")
	)
	(via
		(at 31.876746 -317.166752)
		(size 0.4572)
		(drill 0.2032)
		(layers "F.Cu" "B.Cu")
		(net "GND")
	)
	(via
		(at 347.363034 -237.411514)
		(size 0.4572)
		(drill 0.2032)
		(layers "F.Cu" "B.Cu")
		(net "GND")
	)
	(via
		(at 287.360614 -278.066754)
		(size 0.4572)
		(drill 0.2032)
		(layers "F.Cu" "B.Cu")
		(net "GND")
	)
	(via
		(at 438.033414 -296.766742)
		(size 0.4572)
		(drill 0.2032)
		(layers "F.Cu" "B.Cu")
		(net "GND")
	)
	(via
		(at 342.773762 -273.453098)
		(size 0.4572)
		(drill 0.2032)
		(layers "F.Cu" "B.Cu")
		(net "GND")
	)
	(via
		(at 272.273014 -306.116736)
		(size 0.4572)
		(drill 0.2032)
		(layers "F.Cu" "B.Cu")
		(net "GND")
	)
	(via
		(at 423.836084 -360.148378)
		(size 0.49022)
		(drill 0.254)
		(layers "F.Cu" "B.Cu")
		(net "GND")
	)
	(via
		(at 103.652066 -335.704434)
		(size 0.49022)
		(drill 0.254)
		(layers "F.Cu" "B.Cu")
		(net "GND")
	)
	(via
		(at 458.455014 -216.016586)
		(size 0.4572)
		(drill 0.2032)
		(layers "F.Cu" "B.Cu")
		(net "GND")
	)
	(via
		(at 202.971146 -248.31675)
		(size 0.4572)
		(drill 0.2032)
		(layers "F.Cu" "B.Cu")
		(net "GND")
	)
	(via
		(at 412.84398 -167.731948)
		(size 0.508)
		(drill 0.254)
		(layers "F.Cu" "B.Cu")
		(net "GND")
	)
	(via
		(at 340.541356 -403.249892)
		(size 0.4572)
		(drill 0.254)
		(layers "F.Cu" "B.Cu")
		(net "GND")
	)
	(via
		(at 468.156036 -62.067948)
		(size 0.508)
		(drill 0.254)
		(layers "F.Cu" "B.Cu")
		(net "GND")
	)
	(via
		(at 195.52285 -27.426158)
		(size 0.508)
		(drill 0.254)
		(layers "F.Cu" "B.Cu")
		(net "GND")
	)
	(via
		(at 130.436366 -216.25052)
		(size 0.4572)
		(drill 0.2032)
		(layers "F.Cu" "B.Cu")
		(net "GND")
	)
	(via
		(at 281.707082 -280.61666)
		(size 0.4572)
		(drill 0.2032)
		(layers "F.Cu" "B.Cu")
		(net "GND")
	)
	(via
		(at 97.653094 -283.219906)
		(size 0.4572)
		(drill 0.2032)
		(layers "F.Cu" "B.Cu")
		(net "GND")
	)
	(via
		(at 366.159034 -230.900478)
		(size 0.4572)
		(drill 0.2032)
		(layers "F.Cu" "B.Cu")
		(net "GND")
	)
	(via
		(at 375.087134 -244.73662)
		(size 0.4572)
		(drill 0.2032)
		(layers "F.Cu" "B.Cu")
		(net "GND")
	)
	(via
		(at 124.327412 -230.086662)
		(size 0.4572)
		(drill 0.2032)
		(layers "F.Cu" "B.Cu")
		(net "GND")
	)
	(via
		(at 62.051946 -265.316716)
		(size 0.4572)
		(drill 0.2032)
		(layers "F.Cu" "B.Cu")
		(net "GND")
	)
	(via
		(at 209.281014 -271.266666)
		(size 0.4572)
		(drill 0.2032)
		(layers "F.Cu" "B.Cu")
		(net "GND")
	)
	(via
		(at 153.555954 -407.00452)
		(size 0.4064)
		(drill 0.2032)
		(layers "F.Cu" "B.Cu")
		(net "GND")
	)
	(via
		(at 199.527414 -288.266632)
		(size 0.4572)
		(drill 0.2032)
		(layers "F.Cu" "B.Cu")
		(net "GND")
	)
	(via
		(at 128.28397 -355.244654)
		(size 0.508)
		(drill 0.254)
		(layers "F.Cu" "B.Cu")
		(net "GND")
	)
	(via
		(at 286.773366 -361.625388)
		(size 0.49022)
		(drill 0.254)
		(layers "F.Cu" "B.Cu")
		(net "GND")
	)
	(via
		(at 434.589682 -200.716642)
		(size 0.4572)
		(drill 0.2032)
		(layers "F.Cu" "B.Cu")
		(net "GND")
	)
	(via
		(at 54.3814 -175.355504)
		(size 0.508)
		(drill 0.254)
		(layers "F.Cu" "B.Cu")
		(net "GND")
	)
	(via
		(at 285.150814 -223.666558)
		(size 0.4572)
		(drill 0.2032)
		(layers "F.Cu" "B.Cu")
		(net "GND")
	)
	(via
		(at 453.121014 -315.46673)
		(size 0.4572)
		(drill 0.2032)
		(layers "F.Cu" "B.Cu")
		(net "GND")
	)
	(via
		(at 172.795946 -214.316564)
		(size 0.4572)
		(drill 0.2032)
		(layers "F.Cu" "B.Cu")
		(net "GND")
	)
	(via
		(at 99.422966 -247.178322)
		(size 0.4572)
		(drill 0.2032)
		(layers "F.Cu" "B.Cu")
		(net "GND")
	)
	(via
		(at 20.889214 -301.01667)
		(size 0.4572)
		(drill 0.2032)
		(layers "F.Cu" "B.Cu")
		(net "GND")
	)
	(via
		(at 115.869466 -226.831144)
		(size 0.4572)
		(drill 0.2032)
		(layers "F.Cu" "B.Cu")
		(net "GND")
	)
	(via
		(at 272.273014 -313.766708)
		(size 0.4572)
		(drill 0.2032)
		(layers "F.Cu" "B.Cu")
		(net "GND")
	)
	(via
		(at 230.984044 -49.76495)
		(size 0.508)
		(drill 0.254)
		(layers "F.Cu" "B.Cu")
		(net "GND")
	)
	(via
		(at 225.171 -187.747148)
		(size 0.508)
		(drill 0.254)
		(layers "F.Cu" "B.Cu")
		(net "GND")
	)
	(via
		(at 205.180946 -289.11677)
		(size 0.4572)
		(drill 0.2032)
		(layers "F.Cu" "B.Cu")
		(net "GND")
	)
	(via
		(at 405.648414 -233.016806)
		(size 0.4572)
		(drill 0.2032)
		(layers "F.Cu" "B.Cu")
		(net "GND")
	)
	(via
		(at 98.013012 -236.597952)
		(size 0.4572)
		(drill 0.2032)
		(layers "F.Cu" "B.Cu")
		(net "GND")
	)
	(via
		(at 124.797566 -219.506038)
		(size 0.4572)
		(drill 0.2032)
		(layers "F.Cu" "B.Cu")
		(net "GND")
	)
	(via
		(at 427.504098 -180.86197)
		(size 0.6604)
		(drill 0.3302)
		(layers "F.Cu" "B.Cu")
		(net "GND")
	)
	(via
		(at 306.548282 -286.56661)
		(size 0.4572)
		(drill 0.2032)
		(layers "F.Cu" "B.Cu")
		(net "GND")
	)
	(via
		(at 339.954362 -265.314176)
		(size 0.4572)
		(drill 0.2032)
		(layers "F.Cu" "B.Cu")
		(net "GND")
	)
	(via
		(at 342.303862 -266.128246)
		(size 0.4572)
		(drill 0.2032)
		(layers "F.Cu" "B.Cu")
		(net "GND")
	)
	(via
		(at 439.923682 -204.116686)
		(size 0.4572)
		(drill 0.2032)
		(layers "F.Cu" "B.Cu")
		(net "GND")
	)
	(via
		(at 78.414626 -400.224244)
		(size 0.4572)
		(drill 0.254)
		(layers "F.Cu" "B.Cu")
		(net "GND")
	)
	(via
		(at 430.489614 -268.71676)
		(size 0.4572)
		(drill 0.2032)
		(layers "F.Cu" "B.Cu")
		(net "GND")
	)
	(via
		(at 179.105814 -215.166702)
		(size 0.4572)
		(drill 0.2032)
		(layers "F.Cu" "B.Cu")
		(net "GND")
	)
	(via
		(at 147.188174 -53.436012)
		(size 0.508)
		(drill 0.254)
		(layers "F.Cu" "B.Cu")
		(net "GND")
	)
	(via
		(at 210.514946 -301.866808)
		(size 0.4572)
		(drill 0.2032)
		(layers "F.Cu" "B.Cu")
		(net "GND")
	)
	(via
		(at 159.918146 -242.3668)
		(size 0.4572)
		(drill 0.2032)
		(layers "F.Cu" "B.Cu")
		(net "GND")
	)
	(via
		(at 11.135614 -202.416664)
		(size 0.4572)
		(drill 0.2032)
		(layers "F.Cu" "B.Cu")
		(net "GND")
	)
	(via
		(at 51.064414 -289.966654)
		(size 0.4572)
		(drill 0.2032)
		(layers "F.Cu" "B.Cu")
		(net "GND")
	)
	(via
		(at 184.439814 -310.366664)
		(size 0.4572)
		(drill 0.2032)
		(layers "F.Cu" "B.Cu")
		(net "GND")
	)
	(via
		(at 272.273014 -292.516814)
		(size 0.4572)
		(drill 0.2032)
		(layers "F.Cu" "B.Cu")
		(net "GND")
	)
	(via
		(at 22.123146 -217.716608)
		(size 0.4572)
		(drill 0.2032)
		(layers "F.Cu" "B.Cu")
		(net "GND")
	)
	(via
		(at 9.245346 -260.21665)
		(size 0.4572)
		(drill 0.2032)
		(layers "F.Cu" "B.Cu")
		(net "GND")
	)
	(via
		(at 104.701594 -277.522432)
		(size 0.4572)
		(drill 0.2032)
		(layers "F.Cu" "B.Cu")
		(net "GND")
	)
	(via
		(at 99.422966 -242.294918)
		(size 0.4572)
		(drill 0.2032)
		(layers "F.Cu" "B.Cu")
		(net "GND")
	)
	(via
		(at 23.996142 -177.527204)
		(size 0.508)
		(drill 0.254)
		(layers "F.Cu" "B.Cu")
		(net "GND")
	)
	(via
		(at 173.69028 -20.114768)
		(size 0.508)
		(drill 0.254)
		(layers "F.Cu" "B.Cu")
		(net "GND")
	)
	(via
		(at 61.52261 -38.554152)
		(size 0.508)
		(drill 0.254)
		(layers "F.Cu" "B.Cu")
		(net "GND")
	)
	(via
		(at 314.318396 -407.638504)
		(size 0.4572)
		(drill 0.254)
		(layers "F.Cu" "B.Cu")
		(net "GND")
	)
	(via
		(at 164.989002 -220.266768)
		(size 0.4572)
		(drill 0.2032)
		(layers "F.Cu" "B.Cu")
		(net "GND")
	)
	(via
		(at 66.152014 -299.316648)
		(size 0.4572)
		(drill 0.2032)
		(layers "F.Cu" "B.Cu")
		(net "GND")
	)
	(via
		(at 51.064414 -294.216582)
		(size 0.4572)
		(drill 0.2032)
		(layers "F.Cu" "B.Cu")
		(net "GND")
	)
	(via
		(at 14.579346 -276.366732)
		(size 0.4572)
		(drill 0.2032)
		(layers "F.Cu" "B.Cu")
		(net "GND")
	)
	(via
		(at 214.65413 -12.544552)
		(size 0.508)
		(drill 0.254)
		(layers "F.Cu" "B.Cu")
		(net "GND")
	)
	(via
		(at 283.916882 -245.76659)
		(size 0.4572)
		(drill 0.2032)
		(layers "F.Cu" "B.Cu")
		(net "GND")
	)
	(via
		(at 65.800478 -403.883876)
		(size 0.4064)
		(drill 0.2032)
		(layers "F.Cu" "B.Cu")
		(net "GND")
	)
	(via
		(at 348.772734 -246.364506)
		(size 0.4572)
		(drill 0.2032)
		(layers "F.Cu" "B.Cu")
		(net "GND")
	)
	(via
		(at 157.694884 -203.266802)
		(size 0.4572)
		(drill 0.2032)
		(layers "F.Cu" "B.Cu")
		(net "GND")
	)
	(via
		(at 370.497862 -284.033722)
		(size 0.4572)
		(drill 0.2032)
		(layers "F.Cu" "B.Cu")
		(net "GND")
	)
	(via
		(at 405.648414 -298.466764)
		(size 0.4572)
		(drill 0.2032)
		(layers "F.Cu" "B.Cu")
		(net "GND")
	)
	(via
		(at 422.945814 -246.616728)
		(size 0.4572)
		(drill 0.2032)
		(layers "F.Cu" "B.Cu")
		(net "GND")
	)
	(via
		(at 96.133666 -226.831144)
		(size 0.4572)
		(drill 0.2032)
		(layers "F.Cu" "B.Cu")
		(net "GND")
	)
	(via
		(at 368.916204 -257.28295)
		(size 0.4572)
		(drill 0.2032)
		(layers "F.Cu" "B.Cu")
		(net "GND")
	)
	(via
		(at 233.314748 -132.95122)
		(size 0.508)
		(drill 0.254)
		(layers "F.Cu" "B.Cu")
		(net "GND")
	)
	(via
		(at 135.714994 -266.128246)
		(size 0.4572)
		(drill 0.2032)
		(layers "F.Cu" "B.Cu")
		(net "GND")
	)
	(via
		(at 210.514946 -292.516814)
		(size 0.4572)
		(drill 0.2032)
		(layers "F.Cu" "B.Cu")
		(net "GND")
	)
	(via
		(at 467.535514 -149.72538)
		(size 0.508)
		(drill 0.254)
		(layers "F.Cu" "B.Cu")
		(net "GND")
	)
	(via
		(at 415.402014 -265.316716)
		(size 0.4572)
		(drill 0.2032)
		(layers "F.Cu" "B.Cu")
		(net "GND")
	)
	(via
		(at 121.978166 -234.15625)
		(size 0.4572)
		(drill 0.2032)
		(layers "F.Cu" "B.Cu")
		(net "GND")
	)
	(via
		(at 266.619482 -198.166736)
		(size 0.4572)
		(drill 0.2032)
		(layers "F.Cu" "B.Cu")
		(net "GND")
	)
	(via
		(at 99.532948 -255.547622)
		(size 0.4572)
		(drill 0.2032)
		(layers "F.Cu" "B.Cu")
		(net "GND")
	)
	(via
		(at 458.455014 -270.416782)
		(size 0.4572)
		(drill 0.2032)
		(layers "F.Cu" "B.Cu")
		(net "GND")
	)
	(via
		(at 130.906266 -247.992138)
		(size 0.4572)
		(drill 0.2032)
		(layers "F.Cu" "B.Cu")
		(net "GND")
	)
	(via
		(at 110.340394 -267.755878)
		(size 0.4572)
		(drill 0.2032)
		(layers "F.Cu" "B.Cu")
		(net "GND")
	)
	(via
		(at 194.193414 -297.616626)
		(size 0.4572)
		(drill 0.2032)
		(layers "F.Cu" "B.Cu")
		(net "GND")
	)
	(via
		(at 261.285482 -308.666642)
		(size 0.4572)
		(drill 0.2032)
		(layers "F.Cu" "B.Cu")
		(net "GND")
	)
	(via
		(at 184.439814 -194.766692)
		(size 0.4572)
		(drill 0.2032)
		(layers "F.Cu" "B.Cu")
		(net "GND")
	)
	(via
		(at 66.152014 -308.666642)
		(size 0.4572)
		(drill 0.2032)
		(layers "F.Cu" "B.Cu")
		(net "GND")
	)
	(via
		(at 289.105086 -354.868226)
		(size 0.508)
		(drill 0.254)
		(layers "F.Cu" "B.Cu")
		(net "GND")
	)
	(via
		(at 295.7322 -50.104548)
		(size 0.508)
		(drill 0.254)
		(layers "F.Cu" "B.Cu")
		(net "GND")
	)
	(via
		(at 191.983614 -275.516594)
		(size 0.4572)
		(drill 0.2032)
		(layers "F.Cu" "B.Cu")
		(net "GND")
	)
	(via
		(at 340.424516 -287.28924)
		(size 0.4572)
		(drill 0.2032)
		(layers "F.Cu" "B.Cu")
		(net "GND")
	)
	(via
		(at 190.093346 -307.816758)
		(size 0.4572)
		(drill 0.2032)
		(layers "F.Cu" "B.Cu")
		(net "GND")
	)
	(via
		(at 447.467482 -239.81664)
		(size 0.4572)
		(drill 0.2032)
		(layers "F.Cu" "B.Cu")
		(net "GND")
	)
	(via
		(at 157.349952 -434.899562)
		(size 0.4572)
		(drill 0.2032)
		(layers "F.Cu" "B.Cu")
		(net "GND")
	)
	(via
		(at 398.731232 -5.585714)
		(size 0.508)
		(drill 0.254)
		(layers "F.Cu" "B.Cu")
		(net "GND")
	)
	(via
		(at 119.628666 -221.94774)
		(size 0.4572)
		(drill 0.2032)
		(layers "F.Cu" "B.Cu")
		(net "GND")
	)
	(via
		(at 419.272466 -359.414572)
		(size 0.508)
		(drill 0.254)
		(layers "F.Cu" "B.Cu")
		(net "GND")
	)
	(via
		(at 374.802146 -342.764872)
		(size 0.508)
		(drill 0.254)
		(layers "F.Cu" "B.Cu")
		(net "GND")
	)
	(via
		(at 467.535514 -398.64538)
		(size 0.508)
		(drill 0.254)
		(layers "F.Cu" "B.Cu")
		(net "GND")
	)
	(via
		(at 48.854614 -196.466714)
		(size 0.4572)
		(drill 0.2032)
		(layers "F.Cu" "B.Cu")
		(net "GND")
	)
	(via
		(at 44.754546 -220.266768)
		(size 0.4572)
		(drill 0.2032)
		(layers "F.Cu" "B.Cu")
		(net "GND")
	)
	(via
		(at 427.045882 -297.616626)
		(size 0.4572)
		(drill 0.2032)
		(layers "F.Cu" "B.Cu")
		(net "GND")
	)
	(via
		(at 68.76669 -410.664152)
		(size 0.4572)
		(drill 0.254)
		(layers "F.Cu" "B.Cu")
		(net "GND")
	)
	(via
		(at 176.896014 -291.666676)
		(size 0.4572)
		(drill 0.2032)
		(layers "F.Cu" "B.Cu")
		(net "GND")
	)
	(via
		(at 94.253812 -233.34218)
		(size 0.4572)
		(drill 0.2032)
		(layers "F.Cu" "B.Cu")
		(net "GND")
	)
	(via
		(at 411.958282 -262.76681)
		(size 0.4572)
		(drill 0.2032)
		(layers "F.Cu" "B.Cu")
		(net "GND")
	)
	(via
		(at 191.983614 -289.966654)
		(size 0.4572)
		(drill 0.2032)
		(layers "F.Cu" "B.Cu")
		(net "GND")
	)
	(via
		(at 31.876746 -298.466764)
		(size 0.4572)
		(drill 0.2032)
		(layers "F.Cu" "B.Cu")
		(net "GND")
	)
	(via
		(at 31.876746 -242.3668)
		(size 0.4572)
		(drill 0.2032)
		(layers "F.Cu" "B.Cu")
		(net "GND")
	)
	(via
		(at 98.483166 -219.506038)
		(size 0.4572)
		(drill 0.2032)
		(layers "F.Cu" "B.Cu")
		(net "GND")
	)
	(via
		(at 28.433014 -303.566576)
		(size 0.4572)
		(drill 0.2032)
		(layers "F.Cu" "B.Cu")
		(net "GND")
	)
	(via
		(at 186.15533 -441.225432)
		(size 0.508)
		(drill 0.254)
		(layers "F.Cu" "B.Cu")
		(net "GND")
	)
	(via
		(at 134.195566 -234.15625)
		(size 0.4572)
		(drill 0.2032)
		(layers "F.Cu" "B.Cu")
		(net "GND")
	)
	(via
		(at 396.646908 -9.424924)
		(size 0.508)
		(drill 0.254)
		(layers "F.Cu" "B.Cu")
		(net "GND")
	)
	(via
		(at 341.918798 -49.390046)
		(size 0.4572)
		(drill 0.2032)
		(layers "F.Cu" "B.Cu")
		(net "GND")
	)
	(via
		(at 424.836082 -238.116618)
		(size 0.4572)
		(drill 0.2032)
		(layers "F.Cu" "B.Cu")
		(net "GND")
	)
	(via
		(at 177.561748 -350.093788)
		(size 0.508)
		(drill 0.254)
		(layers "F.Cu" "B.Cu")
		(net "GND")
	)
	(via
		(at 166.80815 -421.035226)
		(size 0.508)
		(drill 0.254)
		(layers "F.Cu" "B.Cu")
		(net "GND")
	)
	(via
		(at 350.822006 -238.26343)
		(size 0.4572)
		(drill 0.2032)
		(layers "F.Cu" "B.Cu")
		(net "GND")
	)
	(via
		(at 396.990062 -404.51786)
		(size 0.4572)
		(drill 0.254)
		(layers "F.Cu" "B.Cu")
		(net "GND")
	)
	(via
		(at 270.063214 -283.166566)
		(size 0.4572)
		(drill 0.2032)
		(layers "F.Cu" "B.Cu")
		(net "GND")
	)
	(via
		(at 327.770744 -343.542874)
		(size 0.49022)
		(drill 0.254)
		(layers "F.Cu" "B.Cu")
		(net "GND")
	)
	(via
		(at 300.238414 -289.11677)
		(size 0.4572)
		(drill 0.2032)
		(layers "F.Cu" "B.Cu")
		(net "GND")
	)
	(via
		(at 395.731238 -401.492212)
		(size 0.4572)
		(drill 0.254)
		(layers "F.Cu" "B.Cu")
		(net "GND")
	)
	(via
		(at 314.092082 -258.516628)
		(size 0.4572)
		(drill 0.2032)
		(layers "F.Cu" "B.Cu")
		(net "GND")
	)
	(via
		(at 147.61845 -41.838118)
		(size 0.508)
		(drill 0.254)
		(layers "F.Cu" "B.Cu")
		(net "GND")
	)
	(via
		(at 418.520118 -407.638504)
		(size 0.4572)
		(drill 0.254)
		(layers "F.Cu" "B.Cu")
		(net "GND")
	)
	(via
		(at 129.147062 -403.249892)
		(size 0.4572)
		(drill 0.254)
		(layers "F.Cu" "B.Cu")
		(net "GND")
	)
	(via
		(at 202.971146 -206.666592)
		(size 0.4572)
		(drill 0.2032)
		(layers "F.Cu" "B.Cu")
		(net "GND")
	)
	(via
		(at 457.221082 -286.56661)
		(size 0.4572)
		(drill 0.2032)
		(layers "F.Cu" "B.Cu")
		(net "GND")
	)
	(via
		(at 285.150814 -276.366732)
		(size 0.4572)
		(drill 0.2032)
		(layers "F.Cu" "B.Cu")
		(net "GND")
	)
	(via
		(at 59.842146 -289.11677)
		(size 0.4572)
		(drill 0.2032)
		(layers "F.Cu" "B.Cu")
		(net "GND")
	)
	(via
		(at 394.923772 -17.601438)
		(size 0.508)
		(drill 0.254)
		(layers "F.Cu" "B.Cu")
		(net "GND")
	)
	(via
		(at 176.896014 -264.466578)
		(size 0.4572)
		(drill 0.2032)
		(layers "F.Cu" "B.Cu")
		(net "GND")
	)
	(via
		(at 175.86452 -11.057128)
		(size 0.508)
		(drill 0.254)
		(layers "F.Cu" "B.Cu")
		(net "GND")
	)
	(via
		(at 39.420546 -296.766742)
		(size 0.4572)
		(drill 0.2032)
		(layers "F.Cu" "B.Cu")
		(net "GND")
	)
	(via
		(at 442.133482 -277.216616)
		(size 0.4572)
		(drill 0.2032)
		(layers "F.Cu" "B.Cu")
		(net "GND")
	)
	(via
		(at 182.549546 -270.416782)
		(size 0.4572)
		(drill 0.2032)
		(layers "F.Cu" "B.Cu")
		(net "GND")
	)
	(via
		(at 167.461946 -199.01662)
		(size 0.4572)
		(drill 0.2032)
		(layers "F.Cu" "B.Cu")
		(net "GND")
	)
	(via
		(at 377.076462 -266.128246)
		(size 0.4572)
		(drill 0.2032)
		(layers "F.Cu" "B.Cu")
		(net "GND")
	)
	(via
		(at 104.231694 -286.475424)
		(size 0.4572)
		(drill 0.2032)
		(layers "F.Cu" "B.Cu")
		(net "GND")
	)
	(via
		(at 268.829282 -196.466714)
		(size 0.4572)
		(drill 0.2032)
		(layers "F.Cu" "B.Cu")
		(net "GND")
	)
	(via
		(at 267.570712 -66.323972)
		(size 0.508)
		(drill 0.254)
		(layers "F.Cu" "B.Cu")
		(net "GND")
	)
	(via
		(at 369.448334 -213.732618)
		(size 0.4572)
		(drill 0.2032)
		(layers "F.Cu" "B.Cu")
		(net "GND")
	)
	(via
		(at 257.185414 -295.06672)
		(size 0.4572)
		(drill 0.2032)
		(layers "F.Cu" "B.Cu")
		(net "GND")
	)
	(via
		(at 195.427346 -251.716794)
		(size 0.4572)
		(drill 0.2032)
		(layers "F.Cu" "B.Cu")
		(net "GND")
	)
	(via
		(at 202.971146 -273.816572)
		(size 0.4572)
		(drill 0.2032)
		(layers "F.Cu" "B.Cu")
		(net "GND")
	)
	(via
		(at 460.664814 -204.96657)
		(size 0.4572)
		(drill 0.2032)
		(layers "F.Cu" "B.Cu")
		(net "GND")
	)
	(via
		(at 194.193414 -266.1666)
		(size 0.4572)
		(drill 0.2032)
		(layers "F.Cu" "B.Cu")
		(net "GND")
	)
	(via
		(at 117.389148 -281.59202)
		(size 0.4572)
		(drill 0.2032)
		(layers "F.Cu" "B.Cu")
		(net "GND")
	)
	(via
		(at 80.43037 -344.90533)
		(size 0.49022)
		(drill 0.254)
		(layers "F.Cu" "B.Cu")
		(net "GND")
	)
	(via
		(at 405.326596 -204.96657)
		(size 0.4572)
		(drill 0.2032)
		(layers "F.Cu" "B.Cu")
		(net "GND")
	)
	(via
		(at 58.608214 -294.216582)
		(size 0.4572)
		(drill 0.2032)
		(layers "F.Cu" "B.Cu")
		(net "GND")
	)
	(via
		(at 47.421038 -400.858228)
		(size 0.4064)
		(drill 0.2032)
		(layers "F.Cu" "B.Cu")
		(net "GND")
	)
	(via
		(at 348.412816 -275.08073)
		(size 0.4572)
		(drill 0.2032)
		(layers "F.Cu" "B.Cu")
		(net "GND")
	)
	(via
		(at 84.541106 -404.51786)
		(size 0.4572)
		(drill 0.254)
		(layers "F.Cu" "B.Cu")
		(net "GND")
	)
	(via
		(at 136.924034 -343.48293)
		(size 0.49022)
		(drill 0.254)
		(layers "F.Cu" "B.Cu")
		(net "GND")
	)
	(via
		(at 346.306648 -400.858228)
		(size 0.4064)
		(drill 0.2032)
		(layers "F.Cu" "B.Cu")
		(net "GND")
	)
	(via
		(at 291.460682 -288.266632)
		(size 0.4572)
		(drill 0.2032)
		(layers "F.Cu" "B.Cu")
		(net "GND")
	)
	(via
		(at 445.577214 -270.416782)
		(size 0.4572)
		(drill 0.2032)
		(layers "F.Cu" "B.Cu")
		(net "GND")
	)
	(via
		(at 420.736014 -238.966756)
		(size 0.4572)
		(drill 0.2032)
		(layers "F.Cu" "B.Cu")
		(net "GND")
	)
	(via
		(at 58.608214 -306.96662)
		(size 0.4572)
		(drill 0.2032)
		(layers "F.Cu" "B.Cu")
		(net "GND")
	)
	(via
		(at 52.298346 -197.316598)
		(size 0.4572)
		(drill 0.2032)
		(layers "F.Cu" "B.Cu")
		(net "GND")
	)
	(via
		(at 413.192214 -260.21665)
		(size 0.4572)
		(drill 0.2032)
		(layers "F.Cu" "B.Cu")
		(net "GND")
	)
	(via
		(at 24.332946 -268.71676)
		(size 0.4572)
		(drill 0.2032)
		(layers "F.Cu" "B.Cu")
		(net "GND")
	)
	(via
		(at 179.105814 -295.916604)
		(size 0.4572)
		(drill 0.2032)
		(layers "F.Cu" "B.Cu")
		(net "GND")
	)
	(via
		(at 379.467618 -360.28503)
		(size 0.6604)
		(drill 0.3302)
		(layers "F.Cu" "B.Cu")
		(net "GND")
	)
	(via
		(at 366.268762 -279.964134)
		(size 0.4572)
		(drill 0.2032)
		(layers "F.Cu" "B.Cu")
		(net "GND")
	)
	(via
		(at 283.916882 -271.266666)
		(size 0.4572)
		(drill 0.2032)
		(layers "F.Cu" "B.Cu")
		(net "GND")
	)
	(via
		(at 342.664034 -219.506038)
		(size 0.4572)
		(drill 0.2032)
		(layers "F.Cu" "B.Cu")
		(net "GND")
	)
	(via
		(at 272.273014 -242.3668)
		(size 0.4572)
		(drill 0.2032)
		(layers "F.Cu" "B.Cu")
		(net "GND")
	)
	(via
		(at 41.324022 -358.528366)
		(size 0.508)
		(drill 0.254)
		(layers "F.Cu" "B.Cu")
		(net "GND")
	)
	(via
		(at 77.173074 -334.915764)
		(size 0.508)
		(drill 0.254)
		(layers "F.Cu" "B.Cu")
		(net "GND")
	)
	(via
		(at 309.992014 -242.3668)
		(size 0.4572)
		(drill 0.2032)
		(layers "F.Cu" "B.Cu")
		(net "GND")
	)
	(via
		(at 54.333648 -147.59559)
		(size 0.49022)
		(drill 0.254)
		(layers "F.Cu" "B.Cu")
		(net "GND")
	)
	(via
		(at 41.310814 -269.566644)
		(size 0.4572)
		(drill 0.2032)
		(layers "F.Cu" "B.Cu")
		(net "GND")
	)
	(via
		(at 82.86623 -341.77097)
		(size 0.49022)
		(drill 0.254)
		(layers "F.Cu" "B.Cu")
		(net "GND")
	)
	(via
		(at 348.08287 -47.482252)
		(size 0.49022)
		(drill 0.254)
		(layers "F.Cu" "B.Cu")
		(net "GND")
	)
	(via
		(at 412.84398 -167.071548)
		(size 0.508)
		(drill 0.254)
		(layers "F.Cu" "B.Cu")
		(net "GND")
	)
	(via
		(at 414.533334 -4.95173)
		(size 0.508)
		(drill 0.254)
		(layers "F.Cu" "B.Cu")
		(net "GND")
	)
	(via
		(at 31.854648 -319.303908)
		(size 0.4572)
		(drill 0.2032)
		(layers "F.Cu" "B.Cu")
		(net "GND")
	)
	(via
		(at 93.784166 -216.25052)
		(size 0.4572)
		(drill 0.2032)
		(layers "F.Cu" "B.Cu")
		(net "GND")
	)
	(via
		(at 307.830728 -407.00452)
		(size 0.4064)
		(drill 0.2032)
		(layers "F.Cu" "B.Cu")
		(net "GND")
	)
	(via
		(at 24.332946 -234.716574)
		(size 0.4572)
		(drill 0.2032)
		(layers "F.Cu" "B.Cu")
		(net "GND")
	)
	(via
		(at 161.925 -28.031948)
		(size 0.508)
		(drill 0.254)
		(layers "F.Cu" "B.Cu")
		(net "GND")
	)
	(via
		(at 428.71644 -359.455466)
		(size 0.508)
		(drill 0.254)
		(layers "F.Cu" "B.Cu")
		(net "GND")
	)
	(via
		(at 210.514946 -276.366732)
		(size 0.4572)
		(drill 0.2032)
		(layers "F.Cu" "B.Cu")
		(net "GND")
	)
	(via
		(at 62.0522 -15.179548)
		(size 0.508)
		(drill 0.254)
		(layers "F.Cu" "B.Cu")
		(net "GND")
	)
	(via
		(at 419.502082 -286.56661)
		(size 0.4572)
		(drill 0.2032)
		(layers "F.Cu" "B.Cu")
		(net "GND")
	)
	(via
		(at 171.562014 -211.766658)
		(size 0.4572)
		(drill 0.2032)
		(layers "F.Cu" "B.Cu")
		(net "GND")
	)
	(via
		(at 28.433014 -275.516594)
		(size 0.4572)
		(drill 0.2032)
		(layers "F.Cu" "B.Cu")
		(net "GND")
	)
	(via
		(at 343.13368 -244.73662)
		(size 0.4572)
		(drill 0.2032)
		(layers "F.Cu" "B.Cu")
		(net "GND")
	)
	(via
		(at 111.640112 -229.272846)
		(size 0.4572)
		(drill 0.2032)
		(layers "F.Cu" "B.Cu")
		(net "GND")
	)
	(via
		(at 177.4444 -134.7978)
		(size 0.508)
		(drill 0.254)
		(layers "F.Cu" "B.Cu")
		(net "GND")
	)
	(via
		(at 176.535588 -345.94546)
		(size 0.508)
		(drill 0.254)
		(layers "F.Cu" "B.Cu")
		(net "GND")
	)
	(via
		(at 455.011282 -235.566712)
		(size 0.4572)
		(drill 0.2032)
		(layers "F.Cu" "B.Cu")
		(net "GND")
	)
	(via
		(at 253.619 -68.544948)
		(size 0.508)
		(drill 0.254)
		(layers "F.Cu" "B.Cu")
		(net "GND")
	)
	(via
		(at 324.853046 -31.386018)
		(size 0.508)
		(drill 0.254)
		(layers "F.Cu" "B.Cu")
		(net "GND")
	)
	(via
		(at 184.439814 -224.516696)
		(size 0.4572)
		(drill 0.2032)
		(layers "F.Cu" "B.Cu")
		(net "GND")
	)
	(via
		(at 359.11028 -233.34218)
		(size 0.4572)
		(drill 0.2032)
		(layers "F.Cu" "B.Cu")
		(net "GND")
	)
	(via
		(at 210.906106 -57.948322)
		(size 0.508)
		(drill 0.254)
		(layers "F.Cu" "B.Cu")
		(net "GND")
	)
	(via
		(at 43.520614 -258.516628)
		(size 0.4572)
		(drill 0.2032)
		(layers "F.Cu" "B.Cu")
		(net "GND")
	)
	(via
		(at 462.555082 -303.566576)
		(size 0.4572)
		(drill 0.2032)
		(layers "F.Cu" "B.Cu")
		(net "GND")
	)
	(via
		(at 52.298346 -229.616762)
		(size 0.4572)
		(drill 0.2032)
		(layers "F.Cu" "B.Cu")
		(net "GND")
	)
	(via
		(at 91.904566 -242.294918)
		(size 0.4572)
		(drill 0.2032)
		(layers "F.Cu" "B.Cu")
		(net "GND")
	)
	(via
		(at 349.27286 -409.396184)
		(size 0.4572)
		(drill 0.254)
		(layers "F.Cu" "B.Cu")
		(net "GND")
	)
	(via
		(at 136.545066 -244.73662)
		(size 0.4572)
		(drill 0.2032)
		(layers "F.Cu" "B.Cu")
		(net "GND")
	)
	(via
		(at 434.589682 -198.166736)
		(size 0.4572)
		(drill 0.2032)
		(layers "F.Cu" "B.Cu")
		(net "GND")
	)
	(via
		(at 274.163282 -271.266666)
		(size 0.4572)
		(drill 0.2032)
		(layers "F.Cu" "B.Cu")
		(net "GND")
	)
	(via
		(at 375.547382 -401.492212)
		(size 0.4572)
		(drill 0.254)
		(layers "F.Cu" "B.Cu")
		(net "GND")
	)
	(via
		(at 207.071214 -247.466612)
		(size 0.4572)
		(drill 0.2032)
		(layers "F.Cu" "B.Cu")
		(net "GND")
	)
	(via
		(at 376.893582 -406.370536)
		(size 0.4572)
		(drill 0.254)
		(layers "F.Cu" "B.Cu")
		(net "GND")
	)
	(via
		(at 338.787994 -59.778392)
		(size 0.49022)
		(drill 0.254)
		(layers "F.Cu" "B.Cu")
		(net "GND")
	)
	(via
		(at 335.615534 -218.692222)
		(size 0.4572)
		(drill 0.2032)
		(layers "F.Cu" "B.Cu")
		(net "GND")
	)
	(via
		(at 337.49488 -230.086662)
		(size 0.4572)
		(drill 0.2032)
		(layers "F.Cu" "B.Cu")
		(net "GND")
	)
	(via
		(at 16.674592 -22.127972)
		(size 0.508)
		(drill 0.254)
		(layers "F.Cu" "B.Cu")
		(net "GND")
	)
	(via
		(at 394.014198 -406.370536)
		(size 0.4572)
		(drill 0.254)
		(layers "F.Cu" "B.Cu")
		(net "GND")
	)
	(via
		(at 54.46395 -351.550732)
		(size 0.508)
		(drill 0.254)
		(layers "F.Cu" "B.Cu")
		(net "GND")
	)
	(via
		(at 335.725262 -261.244842)
		(size 0.4572)
		(drill 0.2032)
		(layers "F.Cu" "B.Cu")
		(net "GND")
	)
	(via
		(at 365.689134 -226.831144)
		(size 0.4572)
		(drill 0.2032)
		(layers "F.Cu" "B.Cu")
		(net "GND")
	)
	(via
		(at 455.011282 -303.566576)
		(size 0.4572)
		(drill 0.2032)
		(layers "F.Cu" "B.Cu")
		(net "GND")
	)
	(via
		(at 16.789146 -278.066754)
		(size 0.4572)
		(drill 0.2032)
		(layers "F.Cu" "B.Cu")
		(net "GND")
	)
	(via
		(at 307.566314 -217.716608)
		(size 0.4572)
		(drill 0.2032)
		(layers "F.Cu" "B.Cu")
		(net "GND")
	)
	(via
		(at 155.272994 -400.858228)
		(size 0.4064)
		(drill 0.2032)
		(layers "F.Cu" "B.Cu")
		(net "GND")
	)
	(via
		(at 90.25001 -439.651394)
		(size 0.4572)
		(drill 0.2032)
		(layers "F.Cu" "B.Cu")
		(net "GND")
	)
	(via
		(at 167.461946 -270.416782)
		(size 0.4572)
		(drill 0.2032)
		(layers "F.Cu" "B.Cu")
		(net "GND")
	)
	(via
		(at 205.938374 -94.64421)
		(size 0.508)
		(drill 0.254)
		(layers "F.Cu" "B.Cu")
		(net "GND")
	)
	(via
		(at 238.401352 -123.240038)
		(size 0.508)
		(drill 0.254)
		(layers "F.Cu" "B.Cu")
		(net "GND")
	)
	(via
		(at 132.425948 -258.80314)
		(size 0.4572)
		(drill 0.2032)
		(layers "F.Cu" "B.Cu")
		(net "GND")
	)
	(via
		(at 48.638714 -294.216582)
		(size 0.4572)
		(drill 0.2032)
		(layers "F.Cu" "B.Cu")
		(net "GND")
	)
	(via
		(at 199.527414 -280.61666)
		(size 0.4572)
		(drill 0.2032)
		(layers "F.Cu" "B.Cu")
		(net "GND")
	)
	(via
		(at 351.579942 -297.078146)
		(size 0.508)
		(drill 0.254)
		(layers "F.Cu" "B.Cu")
		(net "GND")
	)
	(via
		(at 180.339746 -234.716574)
		(size 0.4572)
		(drill 0.2032)
		(layers "F.Cu" "B.Cu")
		(net "GND")
	)
	(via
		(at 102.822248 -282.405836)
		(size 0.4572)
		(drill 0.2032)
		(layers "F.Cu" "B.Cu")
		(net "GND")
	)
	(via
		(at 435.823614 -251.716794)
		(size 0.4572)
		(drill 0.2032)
		(layers "F.Cu" "B.Cu")
		(net "GND")
	)
	(via
		(at 35.976814 -250.866656)
		(size 0.4572)
		(drill 0.2032)
		(layers "F.Cu" "B.Cu")
		(net "GND")
	)
	(via
		(at 90.494866 -234.970066)
		(size 0.4572)
		(drill 0.2032)
		(layers "F.Cu" "B.Cu")
		(net "GND")
	)
	(via
		(at 132.785866 -243.108988)
		(size 0.4572)
		(drill 0.2032)
		(layers "F.Cu" "B.Cu")
		(net "GND")
	)
	(via
		(at 126.316994 -261.244842)
		(size 0.4572)
		(drill 0.2032)
		(layers "F.Cu" "B.Cu")
		(net "GND")
	)
	(via
		(at 165.905942 -403.249892)
		(size 0.4572)
		(drill 0.254)
		(layers "F.Cu" "B.Cu")
		(net "GND")
	)
	(via
		(at 364.389416 -270.19758)
		(size 0.4572)
		(drill 0.2032)
		(layers "F.Cu" "B.Cu")
		(net "GND")
	)
	(via
		(at 443.367414 -276.366732)
		(size 0.4572)
		(drill 0.2032)
		(layers "F.Cu" "B.Cu")
		(net "GND")
	)
	(via
		(at 340.180168 -403.883876)
		(size 0.4064)
		(drill 0.2032)
		(layers "F.Cu" "B.Cu")
		(net "GND")
	)
	(via
		(at 176.896014 -278.916638)
		(size 0.4572)
		(drill 0.2032)
		(layers "F.Cu" "B.Cu")
		(net "GND")
	)
	(via
		(at 139.595606 -403.249892)
		(size 0.4572)
		(drill 0.254)
		(layers "F.Cu" "B.Cu")
		(net "GND")
	)
	(via
		(at 291.460682 -286.56661)
		(size 0.4572)
		(drill 0.2032)
		(layers "F.Cu" "B.Cu")
		(net "GND")
	)
	(via
		(at 363.919262 -275.8948)
		(size 0.4572)
		(drill 0.2032)
		(layers "F.Cu" "B.Cu")
		(net "GND")
	)
	(via
		(at 176.896014 -267.866622)
		(size 0.4572)
		(drill 0.2032)
		(layers "F.Cu" "B.Cu")
		(net "GND")
	)
	(via
		(at 419.502082 -306.96662)
		(size 0.4572)
		(drill 0.2032)
		(layers "F.Cu" "B.Cu")
		(net "GND")
	)
	(via
		(at 31.423864 -5.596636)
		(size 0.508)
		(drill 0.254)
		(layers "F.Cu" "B.Cu")
		(net "GND")
	)
	(via
		(at 337.0199 -410.664152)
		(size 0.4572)
		(drill 0.254)
		(layers "F.Cu" "B.Cu")
		(net "GND")
	)
	(via
		(at 92.954094 -257.175254)
		(size 0.4572)
		(drill 0.2032)
		(layers "F.Cu" "B.Cu")
		(net "GND")
	)
	(via
		(at 148.785326 -401.492212)
		(size 0.4572)
		(drill 0.254)
		(layers "F.Cu" "B.Cu")
		(net "GND")
	)
	(via
		(at 113.989866 -220.319854)
		(size 0.4572)
		(drill 0.2032)
		(layers "F.Cu" "B.Cu")
		(net "GND")
	)
	(via
		(at 382.135634 -219.506038)
		(size 0.4572)
		(drill 0.2032)
		(layers "F.Cu" "B.Cu")
		(net "GND")
	)
	(via
		(at 116.415058 -329.89012)
		(size 0.508)
		(drill 0.254)
		(layers "F.Cu" "B.Cu")
		(net "GND")
	)
	(via
		(at 157.708346 -296.766742)
		(size 0.4572)
		(drill 0.2032)
		(layers "F.Cu" "B.Cu")
		(net "GND")
	)
	(via
		(at 415.519362 -361.726734)
		(size 0.49022)
		(drill 0.254)
		(layers "F.Cu" "B.Cu")
		(net "GND")
	)
	(via
		(at 124.437394 -284.033722)
		(size 0.4572)
		(drill 0.2032)
		(layers "F.Cu" "B.Cu")
		(net "GND")
	)
	(via
		(at 54.508146 -298.466764)
		(size 0.4572)
		(drill 0.2032)
		(layers "F.Cu" "B.Cu")
		(net "GND")
	)
	(via
		(at 211.9376 -72.100948)
		(size 0.508)
		(drill 0.254)
		(layers "F.Cu" "B.Cu")
		(net "GND")
	)
	(via
		(at 393.017248 -147.08632)
		(size 0.508)
		(drill 0.254)
		(layers "F.Cu" "B.Cu")
		(net "GND")
	)
	(via
		(at 161.808414 -267.866622)
		(size 0.4572)
		(drill 0.2032)
		(layers "F.Cu" "B.Cu")
		(net "GND")
	)
	(via
		(at 210.514946 -223.666558)
		(size 0.4572)
		(drill 0.2032)
		(layers "F.Cu" "B.Cu")
		(net "GND")
	)
	(via
		(at 136.54532 -215.436704)
		(size 0.4572)
		(drill 0.2032)
		(layers "F.Cu" "B.Cu")
		(net "GND")
	)
	(via
		(at 308.191916 -407.638504)
		(size 0.4572)
		(drill 0.254)
		(layers "F.Cu" "B.Cu")
		(net "GND")
	)
	(via
		(at 121.303542 -407.638504)
		(size 0.4572)
		(drill 0.254)
		(layers "F.Cu" "B.Cu")
		(net "GND")
	)
	(via
		(at 84.08289 -406.370536)
		(size 0.4572)
		(drill 0.254)
		(layers "F.Cu" "B.Cu")
		(net "GND")
	)
	(via
		(at 152.209754 -400.858228)
		(size 0.4064)
		(drill 0.2032)
		(layers "F.Cu" "B.Cu")
		(net "GND")
	)
	(via
		(at 288.529268 -363.337094)
		(size 0.49022)
		(drill 0.254)
		(layers "F.Cu" "B.Cu")
		(net "GND")
	)
	(via
		(at 14.579346 -227.066602)
		(size 0.4572)
		(drill 0.2032)
		(layers "F.Cu" "B.Cu")
		(net "GND")
	)
	(via
		(at 344.25001 -430.299622)
		(size 0.4572)
		(drill 0.2032)
		(layers "F.Cu" "B.Cu")
		(net "GND")
	)
	(via
		(at 122.557794 -259.616956)
		(size 0.4572)
		(drill 0.2032)
		(layers "F.Cu" "B.Cu")
		(net "GND")
	)
	(via
		(at 375.27357 -410.030168)
		(size 0.4064)
		(drill 0.2032)
		(layers "F.Cu" "B.Cu")
		(net "GND")
	)
	(via
		(at 124.797566 -222.761556)
		(size 0.4572)
		(drill 0.2032)
		(layers "F.Cu" "B.Cu")
		(net "GND")
	)
	(via
		(at 254.69469 -39.101522)
		(size 0.508)
		(drill 0.254)
		(layers "F.Cu" "B.Cu")
		(net "GND")
	)
	(via
		(at 341.80018 -404.51786)
		(size 0.4572)
		(drill 0.254)
		(layers "F.Cu" "B.Cu")
		(net "GND")
	)
	(via
		(at 16.789146 -210.916774)
		(size 0.4572)
		(drill 0.2032)
		(layers "F.Cu" "B.Cu")
		(net "GND")
	)
	(via
		(at 270.063214 -242.3668)
		(size 0.4572)
		(drill 0.2032)
		(layers "F.Cu" "B.Cu")
		(net "GND")
	)
	(via
		(at 37.210746 -290.816792)
		(size 0.4572)
		(drill 0.2032)
		(layers "F.Cu" "B.Cu")
		(net "GND")
	)
	(via
		(at 157.708346 -227.066602)
		(size 0.4572)
		(drill 0.2032)
		(layers "F.Cu" "B.Cu")
		(net "GND")
	)
	(via
		(at 302.448214 -195.616576)
		(size 0.4572)
		(drill 0.2032)
		(layers "F.Cu" "B.Cu")
		(net "GND")
	)
	(via
		(at 187.883546 -307.816758)
		(size 0.4572)
		(drill 0.2032)
		(layers "F.Cu" "B.Cu")
		(net "GND")
	)
	(via
		(at 88.145366 -217.878406)
		(size 0.4572)
		(drill 0.2032)
		(layers "F.Cu" "B.Cu")
		(net "GND")
	)
	(via
		(at 189.40399 -68.407788)
		(size 0.508)
		(drill 0.254)
		(layers "F.Cu" "B.Cu")
		(net "GND")
	)
	(via
		(at 462.555082 -278.916638)
		(size 0.4572)
		(drill 0.2032)
		(layers "F.Cu" "B.Cu")
		(net "GND")
	)
	(via
		(at 209.281014 -211.766658)
		(size 0.4572)
		(drill 0.2032)
		(layers "F.Cu" "B.Cu")
		(net "GND")
	)
	(via
		(at 443.367414 -295.06672)
		(size 0.4572)
		(drill 0.2032)
		(layers "F.Cu" "B.Cu")
		(net "GND")
	)
	(via
		(at 89.664794 -261.244842)
		(size 0.4572)
		(drill 0.2032)
		(layers "F.Cu" "B.Cu")
		(net "GND")
	)
	(via
		(at 397.077438 -407.638504)
		(size 0.4572)
		(drill 0.254)
		(layers "F.Cu" "B.Cu")
		(net "GND")
	)
	(via
		(at 37.210746 -242.3668)
		(size 0.4572)
		(drill 0.2032)
		(layers "F.Cu" "B.Cu")
		(net "GND")
	)
	(via
		(at 48.854614 -284.866588)
		(size 0.4572)
		(drill 0.2032)
		(layers "F.Cu" "B.Cu")
		(net "GND")
	)
	(via
		(at 9.245346 -244.916706)
		(size 0.4572)
		(drill 0.2032)
		(layers "F.Cu" "B.Cu")
		(net "GND")
	)
	(via
		(at 117.075458 -331.21092)
		(size 0.508)
		(drill 0.254)
		(layers "F.Cu" "B.Cu")
		(net "GND")
	)
	(via
		(at 323.991478 -69.198744)
		(size 0.508)
		(drill 0.254)
		(layers "F.Cu" "B.Cu")
		(net "GND")
	)
	(via
		(at 287.360614 -250.016772)
		(size 0.4572)
		(drill 0.2032)
		(layers "F.Cu" "B.Cu")
		(net "GND")
	)
	(via
		(at 360.233214 -402.194014)
		(size 0.508)
		(drill 0.254)
		(layers "F.Cu" "B.Cu")
		(net "GND")
	)
	(via
		(at 413.192214 -225.36658)
		(size 0.4572)
		(drill 0.2032)
		(layers "F.Cu" "B.Cu")
		(net "GND")
	)
	(via
		(at 194.193414 -284.866588)
		(size 0.4572)
		(drill 0.2032)
		(layers "F.Cu" "B.Cu")
		(net "GND")
	)
	(via
		(at 128.666748 -275.08073)
		(size 0.4572)
		(drill 0.2032)
		(layers "F.Cu" "B.Cu")
		(net "GND")
	)
	(via
		(at 388.349998 -433.747164)
		(size 0.4572)
		(drill 0.2032)
		(layers "F.Cu" "B.Cu")
		(net "GND")
	)
	(via
		(at 445.593978 -66.595244)
		(size 0.508)
		(drill 0.254)
		(layers "F.Cu" "B.Cu")
		(net "GND")
	)
	(via
		(at 169.95648 -436.590948)
		(size 0.508)
		(drill 0.254)
		(layers "F.Cu" "B.Cu")
		(net "GND")
	)
	(via
		(at 373.602758 -95.121984)
		(size 0.508)
		(drill 0.254)
		(layers "F.Cu" "B.Cu")
		(net "GND")
	)
	(via
		(at 259.075682 -310.366664)
		(size 0.4572)
		(drill 0.2032)
		(layers "F.Cu" "B.Cu")
		(net "GND")
	)
	(via
		(at 423.513504 -130.944874)
		(size 0.508)
		(drill 0.254)
		(layers "F.Cu" "B.Cu")
		(net "GND")
	)
	(via
		(at 365.219234 -229.272846)
		(size 0.4572)
		(drill 0.2032)
		(layers "F.Cu" "B.Cu")
		(net "GND")
	)
	(via
		(at 24.97709 -19.770344)
		(size 0.508)
		(drill 0.254)
		(layers "F.Cu" "B.Cu")
		(net "GND")
	)
	(via
		(at 384.015234 -239.0394)
		(size 0.4572)
		(drill 0.2032)
		(layers "F.Cu" "B.Cu")
		(net "GND")
	)
	(via
		(at 128.556766 -219.506038)
		(size 0.4572)
		(drill 0.2032)
		(layers "F.Cu" "B.Cu")
		(net "GND")
	)
	(via
		(at 304.122582 -219.41663)
		(size 0.4572)
		(drill 0.2032)
		(layers "F.Cu" "B.Cu")
		(net "GND")
	)
	(via
		(at 337.604862 -254.733552)
		(size 0.4572)
		(drill 0.2032)
		(layers "F.Cu" "B.Cu")
		(net "GND")
	)
	(via
		(at 460.664814 -295.06672)
		(size 0.4572)
		(drill 0.2032)
		(layers "F.Cu" "B.Cu")
		(net "GND")
	)
	(via
		(at 291.460682 -194.766692)
		(size 0.4572)
		(drill 0.2032)
		(layers "F.Cu" "B.Cu")
		(net "GND")
	)
	(via
		(at 345.013534 -244.73662)
		(size 0.4572)
		(drill 0.2032)
		(layers "F.Cu" "B.Cu")
		(net "GND")
	)
	(via
		(at 178.345084 -323.434456)
		(size 0.4572)
		(drill 0.2032)
		(layers "F.Cu" "B.Cu")
		(net "GND")
	)
	(via
		(at 445.04991 -69.570854)
		(size 0.508)
		(drill 0.254)
		(layers "F.Cu" "B.Cu")
		(net "GND")
	)
	(via
		(at 124.753624 -365.433102)
		(size 0.508)
		(drill 0.254)
		(layers "F.Cu" "B.Cu")
		(net "GND")
	)
	(via
		(at 311.427622 -38.809168)
		(size 0.508)
		(drill 0.254)
		(layers "F.Cu" "B.Cu")
		(net "GND")
	)
	(via
		(at 343.243408 -400.858228)
		(size 0.4064)
		(drill 0.2032)
		(layers "F.Cu" "B.Cu")
		(net "GND")
	)
	(via
		(at 197.637146 -233.016806)
		(size 0.4572)
		(drill 0.2032)
		(layers "F.Cu" "B.Cu")
		(net "GND")
	)
	(via
		(at 348.302834 -242.294918)
		(size 0.4572)
		(drill 0.2032)
		(layers "F.Cu" "B.Cu")
		(net "GND")
	)
	(via
		(at 172.795946 -296.766742)
		(size 0.4572)
		(drill 0.2032)
		(layers "F.Cu" "B.Cu")
		(net "GND")
	)
	(via
		(at 32.58185 -169.04081)
		(size 0.508)
		(drill 0.254)
		(layers "F.Cu" "B.Cu")
		(net "GND")
	)
	(via
		(at 312.611008 -403.883876)
		(size 0.4064)
		(drill 0.2032)
		(layers "F.Cu" "B.Cu")
		(net "GND")
	)
	(via
		(at 407.858214 -250.016772)
		(size 0.4572)
		(drill 0.2032)
		(layers "F.Cu" "B.Cu")
		(net "GND")
	)
	(via
		(at 277.607014 -285.716726)
		(size 0.4572)
		(drill 0.2032)
		(layers "F.Cu" "B.Cu")
		(net "GND")
	)
	(via
		(at 439.923682 -221.116652)
		(size 0.4572)
		(drill 0.2032)
		(layers "F.Cu" "B.Cu")
		(net "GND")
	)
	(via
		(at 442.464952 -392.971274)
		(size 0.6604)
		(drill 0.3302)
		(layers "F.Cu" "B.Cu")
		(net "GND")
	)
	(via
		(at 28.433014 -249.166634)
		(size 0.4572)
		(drill 0.2032)
		(layers "F.Cu" "B.Cu")
		(net "GND")
	)
	(via
		(at 340.78418 -245.55069)
		(size 0.4572)
		(drill 0.2032)
		(layers "F.Cu" "B.Cu")
		(net "GND")
	)
	(via
		(at 424.166792 -9.424924)
		(size 0.508)
		(drill 0.254)
		(layers "F.Cu" "B.Cu")
		(net "GND")
	)
	(via
		(at 59.626246 -217.716608)
		(size 0.4572)
		(drill 0.2032)
		(layers "F.Cu" "B.Cu")
		(net "GND")
	)
	(via
		(at 169.42308 -57.343548)
		(size 0.508)
		(drill 0.254)
		(layers "F.Cu" "B.Cu")
		(net "GND")
	)
	(via
		(at 45.657008 -10.16508)
		(size 0.508)
		(drill 0.254)
		(layers "F.Cu" "B.Cu")
		(net "GND")
	)
	(via
		(at 131.849114 -400.858228)
		(size 0.4064)
		(drill 0.2032)
		(layers "F.Cu" "B.Cu")
		(net "GND")
	)
	(via
		(at 344.363294 -45.160692)
		(size 0.4572)
		(drill 0.2032)
		(layers "F.Cu" "B.Cu")
		(net "GND")
	)
	(via
		(at 292.694614 -279.766776)
		(size 0.4572)
		(drill 0.2032)
		(layers "F.Cu" "B.Cu")
		(net "GND")
	)
	(via
		(at 307.566314 -220.342968)
		(size 0.4572)
		(drill 0.2032)
		(layers "F.Cu" "B.Cu")
		(net "GND")
	)
	(via
		(at 58.608214 -244.066568)
		(size 0.4572)
		(drill 0.2032)
		(layers "F.Cu" "B.Cu")
		(net "GND")
	)
	(via
		(at 20.889214 -222.816674)
		(size 0.4572)
		(drill 0.2032)
		(layers "F.Cu" "B.Cu")
		(net "GND")
	)
	(via
		(at 311.882282 -308.666642)
		(size 0.4572)
		(drill 0.2032)
		(layers "F.Cu" "B.Cu")
		(net "GND")
	)
	(via
		(at 175.005746 -265.316716)
		(size 0.4572)
		(drill 0.2032)
		(layers "F.Cu" "B.Cu")
		(net "GND")
	)
	(via
		(at 254.975614 -210.916774)
		(size 0.4572)
		(drill 0.2032)
		(layers "F.Cu" "B.Cu")
		(net "GND")
	)
	(via
		(at 257.185414 -307.816758)
		(size 0.4572)
		(drill 0.2032)
		(layers "F.Cu" "B.Cu")
		(net "GND")
	)
	(via
		(at 449.677282 -264.466578)
		(size 0.4572)
		(drill 0.2032)
		(layers "F.Cu" "B.Cu")
		(net "GND")
	)
	(via
		(at 375.634758 -407.638504)
		(size 0.4572)
		(drill 0.254)
		(layers "F.Cu" "B.Cu")
		(net "GND")
	)
	(via
		(at 164.018214 -247.466612)
		(size 0.4572)
		(drill 0.2032)
		(layers "F.Cu" "B.Cu")
		(net "GND")
	)
	(via
		(at 272.273014 -231.316784)
		(size 0.4572)
		(drill 0.2032)
		(layers "F.Cu" "B.Cu")
		(net "GND")
	)
	(via
		(at 18.679414 -284.866588)
		(size 0.4572)
		(drill 0.2032)
		(layers "F.Cu" "B.Cu")
		(net "GND")
	)
	(via
		(at 12.095226 -106.97337)
		(size 0.508)
		(drill 0.254)
		(layers "F.Cu" "B.Cu")
		(net "GND")
	)
	(via
		(at 334.024732 -342.769952)
		(size 0.508)
		(drill 0.254)
		(layers "F.Cu" "B.Cu")
		(net "GND")
	)
	(via
		(at 201.737214 -280.61666)
		(size 0.4572)
		(drill 0.2032)
		(layers "F.Cu" "B.Cu")
		(net "GND")
	)
	(via
		(at 54.724046 -210.916774)
		(size 0.4572)
		(drill 0.2032)
		(layers "F.Cu" "B.Cu")
		(net "GND")
	)
	(via
		(at 100.942394 -284.033722)
		(size 0.4572)
		(drill 0.2032)
		(layers "F.Cu" "B.Cu")
		(net "GND")
	)
	(via
		(at 63.942214 -198.166736)
		(size 0.4572)
		(drill 0.2032)
		(layers "F.Cu" "B.Cu")
		(net "GND")
	)
	(via
		(at 445.363092 -12.37488)
		(size 0.508)
		(drill 0.254)
		(layers "F.Cu" "B.Cu")
		(net "GND")
	)
	(via
		(at 419.502082 -247.466612)
		(size 0.4572)
		(drill 0.2032)
		(layers "F.Cu" "B.Cu")
		(net "GND")
	)
	(via
		(at 24.345646 -319.344548)
		(size 0.4572)
		(drill 0.2032)
		(layers "F.Cu" "B.Cu")
		(net "GND")
	)
	(via
		(at 384.48488 -234.970066)
		(size 0.4572)
		(drill 0.2032)
		(layers "F.Cu" "B.Cu")
		(net "GND")
	)
	(via
		(at 233.09072 -45.211746)
		(size 0.508)
		(drill 0.254)
		(layers "F.Cu" "B.Cu")
		(net "GND")
	)
	(via
		(at 376.136662 -279.150318)
		(size 0.4572)
		(drill 0.2032)
		(layers "F.Cu" "B.Cu")
		(net "GND")
	)
	(via
		(at 412.393638 -409.396184)
		(size 0.4572)
		(drill 0.254)
		(layers "F.Cu" "B.Cu")
		(net "GND")
	)
	(via
		(at 448.323462 -74.977752)
		(size 0.508)
		(drill 0.254)
		(layers "F.Cu" "B.Cu")
		(net "GND")
	)
	(via
		(at 449.677282 -222.816674)
		(size 0.4572)
		(drill 0.2032)
		(layers "F.Cu" "B.Cu")
		(net "GND")
	)
	(via
		(at 435.823614 -206.666592)
		(size 0.4572)
		(drill 0.2032)
		(layers "F.Cu" "B.Cu")
		(net "GND")
	)
	(via
		(at 428.279814 -287.416748)
		(size 0.4572)
		(drill 0.2032)
		(layers "F.Cu" "B.Cu")
		(net "GND")
	)
	(via
		(at 342.19388 -233.34218)
		(size 0.4572)
		(drill 0.2032)
		(layers "F.Cu" "B.Cu")
		(net "GND")
	)
	(via
		(at 48.854614 -299.316648)
		(size 0.4572)
		(drill 0.2032)
		(layers "F.Cu" "B.Cu")
		(net "GND")
	)
	(via
		(at 314.092336 -55.235348)
		(size 0.508)
		(drill 0.254)
		(layers "F.Cu" "B.Cu")
		(net "GND")
	)
	(via
		(at 216.7128 -190.769748)
		(size 0.508)
		(drill 0.254)
		(layers "F.Cu" "B.Cu")
		(net "GND")
	)
	(via
		(at 236.06252 -387.37794)
		(size 0.508)
		(drill 0.254)
		(layers "F.Cu" "B.Cu")
		(net "GND")
	)
	(via
		(at 387.887718 -406.370536)
		(size 0.4572)
		(drill 0.254)
		(layers "F.Cu" "B.Cu")
		(net "GND")
	)
	(via
		(at 378.846334 -223.575626)
		(size 0.4572)
		(drill 0.2032)
		(layers "F.Cu" "B.Cu")
		(net "GND")
	)
	(via
		(at 450.911214 -225.36658)
		(size 0.4572)
		(drill 0.2032)
		(layers "F.Cu" "B.Cu")
		(net "GND")
	)
	(via
		(at 207.071214 -215.166702)
		(size 0.4572)
		(drill 0.2032)
		(layers "F.Cu" "B.Cu")
		(net "GND")
	)
	(via
		(at 161.808414 -198.166736)
		(size 0.4572)
		(drill 0.2032)
		(layers "F.Cu" "B.Cu")
		(net "GND")
	)
	(via
		(at 207.071214 -235.566712)
		(size 0.4572)
		(drill 0.2032)
		(layers "F.Cu" "B.Cu")
		(net "GND")
	)
	(via
		(at 384.015234 -247.178322)
		(size 0.4318)
		(drill 0.2032)
		(layers "F.Cu" "B.Cu")
		(net "GND")
	)
	(via
		(at 349.27286 -410.664152)
		(size 0.4572)
		(drill 0.254)
		(layers "F.Cu" "B.Cu")
		(net "GND")
	)
	(via
		(at 311.882282 -264.466578)
		(size 0.4572)
		(drill 0.2032)
		(layers "F.Cu" "B.Cu")
		(net "GND")
	)
	(via
		(at 164.018214 -204.116686)
		(size 0.4572)
		(drill 0.2032)
		(layers "F.Cu" "B.Cu")
		(net "GND")
	)
	(via
		(at 93.894148 -265.314176)
		(size 0.4572)
		(drill 0.2032)
		(layers "F.Cu" "B.Cu")
		(net "GND")
	)
	(via
		(at 13.345414 -222.816674)
		(size 0.4572)
		(drill 0.2032)
		(layers "F.Cu" "B.Cu")
		(net "GND")
	)
	(via
		(at 342.774016 -278.336502)
		(size 0.4572)
		(drill 0.2032)
		(layers "F.Cu" "B.Cu")
		(net "GND")
	)
	(via
		(at 257.185414 -317.166752)
		(size 0.4572)
		(drill 0.2032)
		(layers "F.Cu" "B.Cu")
		(net "GND")
	)
	(via
		(at 325.079614 -64.275208)
		(size 0.508)
		(drill 0.254)
		(layers "F.Cu" "B.Cu")
		(net "GND")
	)
	(via
		(at 380.05385 -400.858228)
		(size 0.4064)
		(drill 0.2032)
		(layers "F.Cu" "B.Cu")
		(net "GND")
	)
	(via
		(at 195.427346 -301.866808)
		(size 0.4572)
		(drill 0.2032)
		(layers "F.Cu" "B.Cu")
		(net "GND")
	)
	(via
		(at 127.068834 -407.00452)
		(size 0.4064)
		(drill 0.2032)
		(layers "F.Cu" "B.Cu")
		(net "GND")
	)
	(via
		(at 88.255094 -276.708616)
		(size 0.4572)
		(drill 0.2032)
		(layers "F.Cu" "B.Cu")
		(net "GND")
	)
	(via
		(at 370.968016 -278.336502)
		(size 0.4572)
		(drill 0.2032)
		(layers "F.Cu" "B.Cu")
		(net "GND")
	)
	(via
		(at 441.372752 -323.429376)
		(size 0.4572)
		(drill 0.2032)
		(layers "F.Cu" "B.Cu")
		(net "GND")
	)
	(via
		(at 202.971146 -295.06672)
		(size 0.4572)
		(drill 0.2032)
		(layers "F.Cu" "B.Cu")
		(net "GND")
	)
	(via
		(at 353.727004 -331.776832)
		(size 0.49022)
		(drill 0.254)
		(layers "F.Cu" "B.Cu")
		(net "GND")
	)
	(via
		(at 272.273014 -273.816572)
		(size 0.4572)
		(drill 0.2032)
		(layers "F.Cu" "B.Cu")
		(net "GND")
	)
	(via
		(at 365.76381 -250.337066)
		(size 0.4572)
		(drill 0.2032)
		(layers "F.Cu" "B.Cu")
		(net "GND")
	)
	(via
		(at 242.12169 -247.051068)
		(size 0.508)
		(drill 0.254)
		(layers "F.Cu" "B.Cu")
		(net "GND")
	)
	(via
		(at 360.382312 -334.282034)
		(size 0.49022)
		(drill 0.254)
		(layers "F.Cu" "B.Cu")
		(net "GND")
	)
	(via
		(at 281.707082 -202.416664)
		(size 0.4572)
		(drill 0.2032)
		(layers "F.Cu" "B.Cu")
		(net "GND")
	)
	(via
		(at 453.121014 -301.866808)
		(size 0.4572)
		(drill 0.2032)
		(layers "F.Cu" "B.Cu")
		(net "GND")
	)
	(via
		(at 113.287302 -331.776832)
		(size 0.49022)
		(drill 0.254)
		(layers "F.Cu" "B.Cu")
		(net "GND")
	)
	(via
		(at 57.078118 -19.13636)
		(size 0.508)
		(drill 0.254)
		(layers "F.Cu" "B.Cu")
		(net "GND")
	)
	(via
		(at 323.250052 -427.851316)
		(size 0.4572)
		(drill 0.2032)
		(layers "F.Cu" "B.Cu")
		(net "GND")
	)
	(via
		(at 29.666946 -210.916774)
		(size 0.4572)
		(drill 0.2032)
		(layers "F.Cu" "B.Cu")
		(net "GND")
	)
	(via
		(at 207.071214 -221.116652)
		(size 0.4572)
		(drill 0.2032)
		(layers "F.Cu" "B.Cu")
		(net "GND")
	)
	(via
		(at 130.546094 -289.807142)
		(size 0.4572)
		(drill 0.2032)
		(layers "F.Cu" "B.Cu")
		(net "GND")
	)
	(via
		(at 197.637146 -289.11677)
		(size 0.4572)
		(drill 0.2032)
		(layers "F.Cu" "B.Cu")
		(net "GND")
	)
	(via
		(at 184.439814 -266.1666)
		(size 0.4572)
		(drill 0.2032)
		(layers "F.Cu" "B.Cu")
		(net "GND")
	)
	(via
		(at 133.556502 -409.396184)
		(size 0.4572)
		(drill 0.254)
		(layers "F.Cu" "B.Cu")
		(net "GND")
	)
	(via
		(at 86.845394 -274.266914)
		(size 0.4318)
		(drill 0.2032)
		(layers "F.Cu" "B.Cu")
		(net "GND")
	)
	(via
		(at 324.76694 -406.34666)
		(size 0.4572)
		(drill 0.254)
		(layers "F.Cu" "B.Cu")
		(net "GND")
	)
	(via
		(at 411.958282 -211.766658)
		(size 0.4572)
		(drill 0.2032)
		(layers "F.Cu" "B.Cu")
		(net "GND")
	)
	(via
		(at 14.426946 -387.119876)
		(size 0.508)
		(drill 0.254)
		(layers "F.Cu" "B.Cu")
		(net "GND")
	)
	(via
		(at 296.794682 -299.316648)
		(size 0.4572)
		(drill 0.2032)
		(layers "F.Cu" "B.Cu")
		(net "GND")
	)
	(via
		(at 464.764882 -301.01667)
		(size 0.4572)
		(drill 0.2032)
		(layers "F.Cu" "B.Cu")
		(net "GND")
	)
	(via
		(at 191.983614 -226.216718)
		(size 0.4572)
		(drill 0.2032)
		(layers "F.Cu" "B.Cu")
		(net "GND")
	)
	(via
		(at 384.737102 -400.224244)
		(size 0.4572)
		(drill 0.254)
		(layers "F.Cu" "B.Cu")
		(net "GND")
	)
	(via
		(at 439.29808 -15.687548)
		(size 0.508)
		(drill 0.254)
		(layers "F.Cu" "B.Cu")
		(net "GND")
	)
	(via
		(at 364.588298 -295.038526)
		(size 0.508)
		(drill 0.254)
		(layers "F.Cu" "B.Cu")
		(net "GND")
	)
	(via
		(at 356.373684 -252.074934)
		(size 0.4572)
		(drill 0.2032)
		(layers "F.Cu" "B.Cu")
		(net "GND")
	)
	(via
		(at 84.386166 -229.272846)
		(size 0.4572)
		(drill 0.2032)
		(layers "F.Cu" "B.Cu")
		(net "GND")
	)
	(via
		(at 180.339746 -309.51678)
		(size 0.4572)
		(drill 0.2032)
		(layers "F.Cu" "B.Cu")
		(net "GND")
	)
	(via
		(at 439.923682 -258.516628)
		(size 0.4572)
		(drill 0.2032)
		(layers "F.Cu" "B.Cu")
		(net "GND")
	)
	(via
		(at 258.572 -67.782948)
		(size 0.508)
		(drill 0.254)
		(layers "F.Cu" "B.Cu")
		(net "GND")
	)
	(via
		(at 277.607014 -234.716574)
		(size 0.4572)
		(drill 0.2032)
		(layers "F.Cu" "B.Cu")
		(net "GND")
	)
	(via
		(at 383.184908 -279.964134)
		(size 0.4572)
		(drill 0.2032)
		(layers "F.Cu" "B.Cu")
		(net "GND")
	)
	(via
		(at 175.005746 -258.516628)
		(size 0.4572)
		(drill 0.2032)
		(layers "F.Cu" "B.Cu")
		(net "GND")
	)
	(via
		(at 328.797158 -348.653354)
		(size 0.508)
		(drill 0.254)
		(layers "F.Cu" "B.Cu")
		(net "GND")
	)
	(via
		(at 40.256968 -12.37488)
		(size 0.508)
		(drill 0.254)
		(layers "F.Cu" "B.Cu")
		(net "GND")
	)
	(via
		(at 22.123146 -238.966756)
		(size 0.4572)
		(drill 0.2032)
		(layers "F.Cu" "B.Cu")
		(net "GND")
	)
	(via
		(at 157.708346 -221.96679)
		(size 0.4572)
		(drill 0.2032)
		(layers "F.Cu" "B.Cu")
		(net "GND")
	)
	(via
		(at 447.08064 -374.912128)
		(size 0.49022)
		(drill 0.254)
		(layers "F.Cu" "B.Cu")
		(net "GND")
	)
	(via
		(at 136.349994 -428.851314)
		(size 0.4572)
		(drill 0.2032)
		(layers "F.Cu" "B.Cu")
		(net "GND")
	)
	(via
		(at 16.789146 -212.616796)
		(size 0.4572)
		(drill 0.2032)
		(layers "F.Cu" "B.Cu")
		(net "GND")
	)
	(via
		(at 157.708346 -265.316716)
		(size 0.4572)
		(drill 0.2032)
		(layers "F.Cu" "B.Cu")
		(net "GND")
	)
	(via
		(at 305.128676 -409.396184)
		(size 0.4572)
		(drill 0.254)
		(layers "F.Cu" "B.Cu")
		(net "GND")
	)
	(via
		(at 407.88717 -407.00452)
		(size 0.4064)
		(drill 0.2032)
		(layers "F.Cu" "B.Cu")
		(net "GND")
	)
	(via
		(at 199.527414 -219.41663)
		(size 0.4572)
		(drill 0.2032)
		(layers "F.Cu" "B.Cu")
		(net "GND")
	)
	(via
		(at 136.544812 -239.853216)
		(size 0.4572)
		(drill 0.2032)
		(layers "F.Cu" "B.Cu")
		(net "GND")
	)
	(via
		(at 108.460794 -272.639282)
		(size 0.4572)
		(drill 0.2032)
		(layers "F.Cu" "B.Cu")
		(net "GND")
	)
	(via
		(at 9.245346 -295.06672)
		(size 0.4572)
		(drill 0.2032)
		(layers "F.Cu" "B.Cu")
		(net "GND")
	)
	(via
		(at 80.364838 -197.13575)
		(size 0.508)
		(drill 0.254)
		(layers "F.Cu" "B.Cu")
		(net "GND")
	)
	(via
		(at 21.882608 -4.328668)
		(size 0.508)
		(drill 0.254)
		(layers "F.Cu" "B.Cu")
		(net "GND")
	)
	(via
		(at 40.41775 -113.960656)
		(size 0.508)
		(drill 0.254)
		(layers "F.Cu" "B.Cu")
		(net "GND")
	)
	(via
		(at 79.75473 -60.381896)
		(size 0.508)
		(drill 0.254)
		(layers "F.Cu" "B.Cu")
		(net "GND")
	)
	(via
		(at 283.916882 -221.116652)
		(size 0.4572)
		(drill 0.2032)
		(layers "F.Cu" "B.Cu")
		(net "GND")
	)
	(via
		(at 41.310814 -286.56661)
		(size 0.4572)
		(drill 0.2032)
		(layers "F.Cu" "B.Cu")
		(net "GND")
	)
	(via
		(at 376.88774 -335.187036)
		(size 0.49022)
		(drill 0.254)
		(layers "F.Cu" "B.Cu")
		(net "GND")
	)
	(via
		(at 268.829282 -275.516594)
		(size 0.4572)
		(drill 0.2032)
		(layers "F.Cu" "B.Cu")
		(net "GND")
	)
	(via
		(at 333.23784 -12.616688)
		(size 0.508)
		(drill 0.254)
		(layers "F.Cu" "B.Cu")
		(net "GND")
	)
	(via
		(at 289.250882 -194.766692)
		(size 0.4572)
		(drill 0.2032)
		(layers "F.Cu" "B.Cu")
		(net "GND")
	)
	(via
		(at 44.754546 -285.716726)
		(size 0.4572)
		(drill 0.2032)
		(layers "F.Cu" "B.Cu")
		(net "GND")
	)
	(via
		(at 52.392072 -322.922392)
		(size 0.4572)
		(drill 0.2032)
		(layers "F.Cu" "B.Cu")
		(net "GND")
	)
	(via
		(at 100.942394 -269.38351)
		(size 0.4572)
		(drill 0.2032)
		(layers "F.Cu" "B.Cu")
		(net "GND")
	)
	(via
		(at 167.461946 -279.766776)
		(size 0.4572)
		(drill 0.2032)
		(layers "F.Cu" "B.Cu")
		(net "GND")
	)
	(via
		(at 348.141544 -57.732168)
		(size 0.49022)
		(drill 0.254)
		(layers "F.Cu" "B.Cu")
		(net "GND")
	)
	(via
		(at 95.077026 -410.664152)
		(size 0.4572)
		(drill 0.254)
		(layers "F.Cu" "B.Cu")
		(net "GND")
	)
	(via
		(at 128.688846 -407.638504)
		(size 0.4572)
		(drill 0.254)
		(layers "F.Cu" "B.Cu")
		(net "GND")
	)
	(via
		(at 365.799116 -279.150318)
		(size 0.4572)
		(drill 0.2032)
		(layers "F.Cu" "B.Cu")
		(net "GND")
	)
	(via
		(at 141.968982 -336.869532)
		(size 0.508)
		(drill 0.254)
		(layers "F.Cu" "B.Cu")
		(net "GND")
	)
	(via
		(at 415.402014 -201.56678)
		(size 0.4572)
		(drill 0.2032)
		(layers "F.Cu" "B.Cu")
		(net "GND")
	)
	(via
		(at 367.056924 -326.938132)
		(size 0.508)
		(drill 0.254)
		(layers "F.Cu" "B.Cu")
		(net "GND")
	)
	(via
		(at 333.845662 -282.405836)
		(size 0.4572)
		(drill 0.2032)
		(layers "F.Cu" "B.Cu")
		(net "GND")
	)
	(via
		(at 131.846066 -249.620024)
		(size 0.4572)
		(drill 0.2032)
		(layers "F.Cu" "B.Cu")
		(net "GND")
	)
	(via
		(at 130.546348 -279.964134)
		(size 0.4572)
		(drill 0.2032)
		(layers "F.Cu" "B.Cu")
		(net "GND")
	)
	(via
		(at 238.911384 -126.656592)
		(size 0.508)
		(drill 0.254)
		(layers "F.Cu" "B.Cu")
		(net "GND")
	)
	(via
		(at 337.29168 -21.442172)
		(size 0.49022)
		(drill 0.254)
		(layers "F.Cu" "B.Cu")
		(net "GND")
	)
	(via
		(at 58.608214 -301.01667)
		(size 0.4572)
		(drill 0.2032)
		(layers "F.Cu" "B.Cu")
		(net "GND")
	)
	(via
		(at 270.063214 -287.416748)
		(size 0.4572)
		(drill 0.2032)
		(layers "F.Cu" "B.Cu")
		(net "GND")
	)
	(via
		(at 171.562014 -258.516628)
		(size 0.4572)
		(drill 0.2032)
		(layers "F.Cu" "B.Cu")
		(net "GND")
	)
	(via
		(at 372.571518 -406.370536)
		(size 0.4572)
		(drill 0.254)
		(layers "F.Cu" "B.Cu")
		(net "GND")
	)
	(via
		(at 91.904312 -237.411514)
		(size 0.4572)
		(drill 0.2032)
		(layers "F.Cu" "B.Cu")
		(net "GND")
	)
	(via
		(at 216.824814 -303.566576)
		(size 0.4572)
		(drill 0.2032)
		(layers "F.Cu" "B.Cu")
		(net "GND")
	)
	(via
		(at 261.285482 -316.316614)
		(size 0.4572)
		(drill 0.2032)
		(layers "F.Cu" "B.Cu")
		(net "GND")
	)
	(via
		(at 104.591866 -217.064336)
		(size 0.4572)
		(drill 0.2032)
		(layers "F.Cu" "B.Cu")
		(net "GND")
	)
	(via
		(at 290.975542 -360.840274)
		(size 0.49022)
		(drill 0.254)
		(layers "F.Cu" "B.Cu")
		(net "GND")
	)
	(via
		(at 302.448214 -233.016806)
		(size 0.4572)
		(drill 0.2032)
		(layers "F.Cu" "B.Cu")
		(net "GND")
	)
	(arc
		(start 98.123248 -273.730974)
		(mid 98.123184 -273.998944)
		(end 98.122994 -274.266914)
		(width 0.2032)
		(layer "F.Cu")
		(net "GND")
	)
	(arc
		(start 345.593162 -272.917158)
		(mid 345.593225 -273.185128)
		(end 345.593416 -273.453098)
		(width 0.2032)
		(layer "F.Cu")
		(net "GND")
	)
	(arc
		(start 344.183716 -254.733044)
		(mid 344.183658 -254.733336)
		(end 344.183462 -254.733552)
		(width 0.2032)
		(layer "F.Cu")
		(net "GND")
	)
	(arc
		(start 93.893894 -274.54479)
		(mid 93.893957 -274.81276)
		(end 93.894148 -275.08073)
		(width 0.2032)
		(layer "F.Cu")
		(net "GND")
	)
	(arc
		(start 344.183716 -262.336534)
		(mid 344.183652 -262.604504)
		(end 344.183462 -262.872474)
		(width 0.2032)
		(layer "F.Cu")
		(net "GND")
	)
	(arc
		(start 99.532694 -263.150604)
		(mid 99.532757 -263.418574)
		(end 99.532948 -263.686544)
		(width 0.2032)
		(layer "F.Cu")
		(net "GND")
	)
	(arc
		(start 100.942648 -259.081016)
		(mid 100.942584 -259.348986)
		(end 100.942394 -259.616956)
		(width 0.254)
		(layer "F.Cu")
		(net "GND")
	)
	(arc
		(start 92.954094 -258.2672)
		(mid 92.954157 -258.53517)
		(end 92.954348 -258.80314)
		(width 0.2032)
		(layer "F.Cu")
		(net "GND")
	)
	(arc
		(start 342.773762 -256.639314)
		(mid 342.773825 -256.907284)
		(end 342.774016 -257.175254)
		(width 0.2032)
		(layer "F.Cu")
		(net "GND")
	)
	(arc
		(start 340.894162 -258.2672)
		(mid 340.894225 -258.53517)
		(end 340.894416 -258.80314)
		(width 0.2032)
		(layer "F.Cu")
		(net "GND")
	)
	(arc
		(start 96.243648 -254.733044)
		(mid 96.24359 -254.733336)
		(end 96.243394 -254.733552)
		(width 0.2032)
		(layer "F.Cu")
		(net "GND")
	)
	(arc
		(start 99.532694 -272.917158)
		(mid 99.532757 -273.185128)
		(end 99.532948 -273.453098)
		(width 0.2032)
		(layer "F.Cu")
		(net "GND")
	)
	(arc
		(start 340.894162 -259.894832)
		(mid 340.894225 -260.162802)
		(end 340.894416 -260.430772)
		(width 0.2032)
		(layer "F.Cu")
		(net "GND")
	)
	(arc
		(start 92.954094 -259.894832)
		(mid 92.954157 -260.162802)
		(end 92.954348 -260.430772)
		(width 0.2032)
		(layer "F.Cu")
		(net "GND")
	)
	(arc
		(start 345.123516 -276.986492)
		(mid 345.123452 -277.254462)
		(end 345.123262 -277.522432)
		(width 0.2032)
		(layer "F.Cu")
		(net "GND")
	)
	(arc
		(start 94.364048 -259.081016)
		(mid 94.363984 -259.348986)
		(end 94.363794 -259.616956)
		(width 0.2032)
		(layer "F.Cu")
		(net "GND")
	)
	(arc
		(start 95.303848 -262.336534)
		(mid 95.303784 -262.604504)
		(end 95.303594 -262.872474)
		(width 0.2032)
		(layer "F.Cu")
		(net "GND")
	)
	(arc
		(start 348.882716 -259.081016)
		(mid 348.882652 -259.348986)
		(end 348.882462 -259.616956)
		(width 0.254)
		(layer "F.Cu")
		(net "GND")
	)
	(arc
		(start 354.051362 -264.778236)
		(mid 354.051425 -265.046206)
		(end 354.051616 -265.314176)
		(width 0.254)
		(layer "F.Cu")
		(net "GND")
	)
	(arc
		(start 93.893894 -259.894832)
		(mid 93.893957 -260.162802)
		(end 93.894148 -260.430772)
		(width 0.2032)
		(layer "F.Cu")
		(net "GND")
	)
	(arc
		(start 347.472762 -274.54479)
		(mid 347.472825 -274.81276)
		(end 347.473016 -275.08073)
		(width 0.2032)
		(layer "F.Cu")
		(net "GND")
	)
	(arc
		(start 96.243648 -276.986492)
		(mid 96.243584 -277.254462)
		(end 96.243394 -277.522432)
		(width 0.2032)
		(layer "F.Cu")
		(net "GND")
	)
	(arc
		(start 341.833962 -274.54479)
		(mid 341.834025 -274.81276)
		(end 341.834216 -275.08073)
		(width 0.2032)
		(layer "F.Cu")
		(net "GND")
	)
	(arc
		(start 101.412294 -266.405868)
		(mid 101.412357 -266.673838)
		(end 101.412548 -266.941808)
		(width 0.254)
		(layer "F.Cu")
		(net "GND")
	)
	(arc
		(start 348.882716 -254.733044)
		(mid 348.882658 -254.733336)
		(end 348.882462 -254.733552)
		(width 0.2032)
		(layer "F.Cu")
		(net "GND")
	)
	(arc
		(start 346.063316 -273.730974)
		(mid 346.063252 -273.998944)
		(end 346.063062 -274.266914)
		(width 0.2032)
		(layer "F.Cu")
		(net "GND")
	)
	(arc
		(start 96.243648 -270.475456)
		(mid 96.243584 -270.743426)
		(end 96.243394 -271.011396)
		(width 0.2032)
		(layer "F.Cu")
		(net "GND")
	)
	(arc
		(start 342.304116 -259.081016)
		(mid 342.304052 -259.348986)
		(end 342.303862 -259.616956)
		(width 0.2032)
		(layer "F.Cu")
		(net "GND")
	)
	(arc
		(start 339.014562 -258.2672)
		(mid 339.014625 -258.53517)
		(end 339.014816 -258.80314)
		(width 0.2032)
		(layer "F.Cu")
		(net "GND")
	)
	(arc
		(start 341.833962 -259.894832)
		(mid 341.834025 -260.162802)
		(end 341.834216 -260.430772)
		(width 0.2032)
		(layer "F.Cu")
		(net "GND")
	)
	(arc
		(start 94.364048 -273.730974)
		(mid 94.363984 -273.998944)
		(end 94.363794 -274.266914)
		(width 0.2032)
		(layer "F.Cu")
		(net "GND")
	)
	(arc
		(start 347.472762 -266.405868)
		(mid 347.472825 -266.673838)
		(end 347.473016 -266.941808)
		(width 0.2032)
		(layer "F.Cu")
		(net "GND")
	)
	(arc
		(start 91.074494 -258.2672)
		(mid 91.074557 -258.53517)
		(end 91.074748 -258.80314)
		(width 0.2032)
		(layer "F.Cu")
		(net "GND")
	)
	(arc
		(start 96.243648 -257.45313)
		(mid 96.243584 -257.7211)
		(end 96.243394 -257.98907)
		(width 0.2032)
		(layer "F.Cu")
		(net "GND")
	)
	(arc
		(start 344.183716 -276.986492)
		(mid 344.183652 -277.254462)
		(end 344.183462 -277.522432)
		(width 0.2032)
		(layer "F.Cu")
		(net "GND")
	)
	(arc
		(start 96.243648 -259.081016)
		(mid 96.243584 -259.348986)
		(end 96.243394 -259.616956)
		(width 0.2032)
		(layer "F.Cu")
		(net "GND")
	)
	(arc
		(start 96.243648 -255.825498)
		(mid 96.243584 -256.093468)
		(end 96.243394 -256.361438)
		(width 0.2032)
		(layer "F.Cu")
		(net "GND")
	)
	(arc
		(start 343.243916 -276.986492)
		(mid 343.243852 -277.254462)
		(end 343.243662 -277.522432)
		(width 0.2032)
		(layer "F.Cu")
		(net "GND")
	)
	(arc
		(start 99.532694 -266.405868)
		(mid 99.532757 -266.673838)
		(end 99.532948 -266.941808)
		(width 0.2032)
		(layer "F.Cu")
		(net "GND")
	)
	(arc
		(start 344.183716 -255.825498)
		(mid 344.183652 -256.093468)
		(end 344.183462 -256.361438)
		(width 0.2032)
		(layer "F.Cu")
		(net "GND")
	)
	(arc
		(start 356.870762 -264.778236)
		(mid 356.870825 -265.046206)
		(end 356.871016 -265.314176)
		(width 0.254)
		(layer "F.Cu")
		(net "GND")
	)
	(arc
		(start 342.773762 -261.522718)
		(mid 342.773825 -261.790688)
		(end 342.774016 -262.058658)
		(width 0.2032)
		(layer "F.Cu")
		(net "GND")
	)
	(arc
		(start 344.183716 -273.730974)
		(mid 344.183652 -273.998944)
		(end 344.183462 -274.266914)
		(width 0.2032)
		(layer "F.Cu")
		(net "GND")
	)
	(arc
		(start 95.303848 -276.986492)
		(mid 95.303784 -277.254462)
		(end 95.303594 -277.522432)
		(width 0.2032)
		(layer "F.Cu")
		(net "GND")
	)
	(arc
		(start 106.111294 -264.778236)
		(mid 106.111357 -265.046206)
		(end 106.111548 -265.314176)
		(width 0.254)
		(layer "F.Cu")
		(net "GND")
	)
	(arc
		(start 345.593162 -263.150604)
		(mid 345.593225 -263.418574)
		(end 345.593416 -263.686544)
		(width 0.2032)
		(layer "F.Cu")
		(net "GND")
	)
	(arc
		(start 94.833694 -261.522718)
		(mid 94.833757 -261.790688)
		(end 94.833948 -262.058658)
		(width 0.2032)
		(layer "F.Cu")
		(net "GND")
	)
	(arc
		(start 99.532694 -274.54479)
		(mid 99.532757 -274.81276)
		(end 99.532948 -275.08073)
		(width 0.2032)
		(layer "F.Cu")
		(net "GND")
	)
	(arc
		(start 340.894162 -261.522718)
		(mid 340.894225 -261.790688)
		(end 340.894416 -262.058658)
		(width 0.2032)
		(layer "F.Cu")
		(net "GND")
	)
	(arc
		(start 348.882716 -273.730974)
		(mid 348.882652 -273.998944)
		(end 348.882462 -274.266914)
		(width 0.254)
		(layer "F.Cu")
		(net "GND")
	)
	(arc
		(start 96.243648 -273.730974)
		(mid 96.243584 -273.998944)
		(end 96.243394 -274.266914)
		(width 0.2032)
		(layer "F.Cu")
		(net "GND")
	)
	(arc
		(start 348.412562 -274.54479)
		(mid 348.412625 -274.81276)
		(end 348.412816 -275.08073)
		(width 0.254)
		(layer "F.Cu")
		(net "GND")
	)
	(arc
		(start 343.243916 -262.336534)
		(mid 343.243852 -262.604504)
		(end 343.243662 -262.872474)
		(width 0.2032)
		(layer "F.Cu")
		(net "GND")
	)
	(arc
		(start 97.653094 -272.917158)
		(mid 97.653157 -273.185128)
		(end 97.653348 -273.453098)
		(width 0.2032)
		(layer "F.Cu")
		(net "GND")
	)
	(arc
		(start 101.882448 -275.35886)
		(mid 101.882384 -275.62683)
		(end 101.882194 -275.8948)
		(width 0.254)
		(layer "F.Cu")
		(net "GND")
	)
	(arc
		(start 96.243648 -262.336534)
		(mid 96.243584 -262.604504)
		(end 96.243394 -262.872474)
		(width 0.2032)
		(layer "F.Cu")
		(net "GND")
	)
	(arc
		(start 349.352362 -266.405868)
		(mid 349.352425 -266.673838)
		(end 349.352616 -266.941808)
		(width 0.254)
		(layer "F.Cu")
		(net "GND")
	)
	(arc
		(start 92.954094 -274.54479)
		(mid 92.954157 -274.81276)
		(end 92.954348 -275.08073)
		(width 0.2032)
		(layer "F.Cu")
		(net "GND")
	)
	(arc
		(start 349.822516 -254.733044)
		(mid 349.822458 -254.733336)
		(end 349.822262 -254.733552)
		(width 0.2032)
		(layer "F.Cu")
		(net "GND")
	)
	(arc
		(start 344.183716 -270.475456)
		(mid 344.183652 -270.743426)
		(end 344.183462 -271.011396)
		(width 0.2032)
		(layer "F.Cu")
		(net "GND")
	)
	(arc
		(start 347.472762 -263.150604)
		(mid 347.472825 -263.418574)
		(end 347.473016 -263.686544)
		(width 0.2032)
		(layer "F.Cu")
		(net "GND")
	)
	(arc
		(start 92.954094 -261.522718)
		(mid 92.954157 -261.790688)
		(end 92.954348 -262.058658)
		(width 0.2032)
		(layer "F.Cu")
		(net "GND")
	)
	(arc
		(start 340.894162 -274.54479)
		(mid 340.894225 -274.81276)
		(end 340.894416 -275.08073)
		(width 0.2032)
		(layer "F.Cu")
		(net "GND")
	)
	(arc
		(start 108.930694 -264.778236)
		(mid 108.930757 -265.046206)
		(end 108.930948 -265.314176)
		(width 0.254)
		(layer "F.Cu")
		(net "GND")
	)
	(arc
		(start 100.472494 -274.54479)
		(mid 100.472557 -274.81276)
		(end 100.472748 -275.08073)
		(width 0.254)
		(layer "F.Cu")
		(net "GND")
	)
	(arc
		(start 342.304116 -273.730974)
		(mid 342.304052 -273.998944)
		(end 342.303862 -274.266914)
		(width 0.2032)
		(layer "F.Cu")
		(net "GND")
	)
	(arc
		(start 344.183716 -257.45313)
		(mid 344.183652 -257.7211)
		(end 344.183462 -257.98907)
		(width 0.2032)
		(layer "F.Cu")
		(net "GND")
	)
	(arc
		(start 97.653094 -263.150604)
		(mid 97.653157 -263.418574)
		(end 97.653348 -263.686544)
		(width 0.2032)
		(layer "F.Cu")
		(net "GND")
	)
	(arc
		(start 100.942648 -254.733044)
		(mid 100.94259 -254.733336)
		(end 100.942394 -254.733552)
		(width 0.2032)
		(layer "F.Cu")
		(net "GND")
	)
	(arc
		(start 347.472762 -272.917158)
		(mid 347.472825 -273.185128)
		(end 347.473016 -273.453098)
		(width 0.2032)
		(layer "F.Cu")
		(net "GND")
	)
	(arc
		(start 101.882448 -254.733044)
		(mid 101.88239 -254.733336)
		(end 101.882194 -254.733552)
		(width 0.2032)
		(layer "F.Cu")
		(net "GND")
	)
	(arc
		(start 344.183716 -259.081016)
		(mid 344.183652 -259.348986)
		(end 344.183462 -259.616956)
		(width 0.2032)
		(layer "F.Cu")
		(net "GND")
	)
	(arc
		(start 94.833694 -256.639314)
		(mid 94.833757 -256.907284)
		(end 94.833948 -257.175254)
		(width 0.2032)
		(layer "F.Cu")
		(net "GND")
	)
	(arc
		(start 97.183448 -276.986492)
		(mid 97.183384 -277.254462)
		(end 97.183194 -277.522432)
		(width 0.2032)
		(layer "F.Cu")
		(net "GND")
	)
	(arc
		(start 100.942648 -273.730974)
		(mid 100.942584 -273.998944)
		(end 100.942394 -274.266914)
		(width 0.254)
		(layer "F.Cu")
		(net "GND")
	)
	(segment
		(start 210.711034 -75.313794)
		(end 212.216746 -75.313794)
		(width 0.3556)
		(layer "B.Cu")
		(net "GND")
	)
	(segment
		(start 250.33224 -107.770168)
		(end 250.775216 -107.327192)
		(width 0.381)
		(layer "B.Cu")
		(net "GND")
	)
	(segment
		(start 23.69693 -193.552826)
		(end 24.327866 -193.552826)
		(width 0.3556)
		(layer "B.Cu")
		(net "GND")
	)
	(segment
		(start 330.73848 -25.695148)
		(end 330.73848 -25.256998)
		(width 0.3556)
		(layer "B.Cu")
		(net "GND")
	)
	(segment
		(start 406.70226 -340.825328)
		(end 406.70226 -380.507748)
		(width 0.3556)
		(layer "B.Cu")
		(net "GND")
	)
	(segment
		(start 456.052936 -380.085854)
		(end 455.26833 -380.87046)
		(width 0.3556)
		(layer "B.Cu")
		(net "GND")
	)
	(segment
		(start 325.702422 -63.236348)
		(end 326.16648 -62.77229)
		(width 0.381)
		(layer "B.Cu")
		(net "GND")
	)
	(segment
		(start 405.496776 -54.743604)
		(end 405.486108 -54.754272)
		(width 0.3556)
		(layer "B.Cu")
		(net "GND")
	)
	(segment
		(start 279.124664 -319.263776)
		(end 279.164796 -319.303908)
		(width 0.3556)
		(layer "B.Cu")
		(net "GND")
	)
	(segment
		(start 176.140364 -335.483962)
		(end 177.156364 -335.483962)
		(width 0.508)
		(layer "B.Cu")
		(net "GND")
	)
	(segment
		(start 37.356542 -132.783834)
		(end 37.977572 -132.79374)
		(width 0.381)
		(layer "B.Cu")
		(net "GND")
	)
	(segment
		(start 294.421052 -319.263776)
		(end 294.91051 -319.753234)
		(width 0.3556)
		(layer "B.Cu")
		(net "GND")
	)
	(segment
		(start 380.75108 -185.738008)
		(end 381.608584 -185.738008)
		(width 0.3556)
		(layer "B.Cu")
		(net "GND")
	)
	(segment
		(start 97.46996 -423.436288)
		(end 97.46996 -422.543478)
		(width 0.3556)
		(layer "B.Cu")
		(net "GND")
	)
	(segment
		(start 184.155588 -121.375424)
		(end 184.155588 -121.50852)
		(width 0.3556)
		(layer "B.Cu")
		(net "GND")
	)
	(segment
		(start 158.718504 -42.205148)
		(end 158.707074 -42.216578)
		(width 0.3556)
		(layer "B.Cu")
		(net "GND")
	)
	(segment
		(start 456.337162 -48.778668)
		(end 457.0349 -49.476406)
		(width 0.508)
		(layer "B.Cu")
		(net "GND")
	)
	(segment
		(start 148.28393 -189.963298)
		(end 148.699474 -189.963298)
		(width 0.3556)
		(layer "B.Cu")
		(net "GND")
	)
	(segment
		(start 436.17896 -44.45254)
		(end 436.17896 -45.49394)
		(width 0.3556)
		(layer "B.Cu")
		(net "GND")
	)
	(segment
		(start 340.17712 -32.04845)
		(end 340.17712 -31.9659)
		(width 0.3556)
		(layer "B.Cu")
		(net "GND")
	)
	(segment
		(start 13.400532 -112.519206)
		(end 12.876784 -112.519206)
		(width 0.2032)
		(layer "B.Cu")
		(net "GND")
	)
	(segment
		(start 341.161624 -53.908706)
		(end 340.921086 -53.908706)
		(width 0.381)
		(layer "B.Cu")
		(net "GND")
	)
	(segment
		(start 292.556692 -344.700352)
		(end 293.497 -344.700352)
		(width 0.508)
		(layer "B.Cu")
		(net "GND")
	)
	(segment
		(start 193.78041 -118.074948)
		(end 194.39001 -118.074948)
		(width 0.3556)
		(layer "B.Cu")
		(net "GND")
	)
	(segment
		(start 7.79272 -113.161826)
		(end 7.79272 -112.04702)
		(width 0.3556)
		(layer "B.Cu")
		(net "GND")
	)
	(segment
		(start 263.398 -74.502518)
		(end 263.398 -74.532998)
		(width 0.3556)
		(layer "B.Cu")
		(net "GND")
	)
	(segment
		(start 263.064752 -100.243132)
		(end 262.392414 -100.91547)
		(width 0.3556)
		(layer "B.Cu")
		(net "GND")
	)
	(segment
		(start 259.440426 -77.648816)
		(end 259.064506 -77.272896)
		(width 0.381)
		(layer "B.Cu")
		(net "GND")
	)
	(segment
		(start 433.297584 -178.964844)
		(end 433.297584 -179.418488)
		(width 0.3556)
		(layer "B.Cu")
		(net "GND")
	)
	(segment
		(start 238.767874 -126.513082)
		(end 238.244126 -126.513082)
		(width 0.3556)
		(layer "B.Cu")
		(net "GND")
	)
	(segment
		(start 377.814332 -270.695674)
		(end 377.829064 -270.687038)
		(width 0.0889)
		(layer "B.Cu")
		(net "GND")
	)
	(segment
		(start 120.476264 -270.695674)
		(end 120.490996 -270.687038)
		(width 0.0889)
		(layer "B.Cu")
		(net "GND")
	)
	(segment
		(start 311.44083 -55.336948)
		(end 310.82488 -55.336948)
		(width 0.3556)
		(layer "B.Cu")
		(net "GND")
	)
	(segment
		(start 137.80262 -30.557978)
		(end 138.77798 -30.557978)
		(width 0.3556)
		(layer "B.Cu")
		(net "GND")
	)
	(segment
		(start 198.47814 -109.682788)
		(end 198.264018 -109.89691)
		(width 0.3556)
		(layer "B.Cu")
		(net "GND")
	)
	(segment
		(start 153.88082 -102.306628)
		(end 154.549602 -101.637846)
		(width 0.3556)
		(layer "B.Cu")
		(net "GND")
	)
	(segment
		(start 212.812884 -319.268856)
		(end 213.18093 -318.90081)
		(width 0.381)
		(layer "B.Cu")
		(net "GND")
	)
	(segment
		(start 283.916882 -194.766692)
		(end 284.446726 -194.236848)
		(width 0.3556)
		(layer "B.Cu")
		(net "GND")
	)
	(segment
		(start 60.468002 -8.719312)
		(end 60.468002 -9.439148)
		(width 0.3556)
		(layer "B.Cu")
		(net "GND")
	)
	(segment
		(start 371.673628 -190.01994)
		(end 371.421914 -190.271654)
		(width 0.3556)
		(layer "B.Cu")
		(net "GND")
	)
	(segment
		(start 385.252214 -271.500854)
		(end 385.266946 -271.50949)
		(width 0.0889)
		(layer "B.Cu")
		(net "GND")
	)
	(segment
		(start 173.755558 -121.528586)
		(end 174.002446 -121.775474)
		(width 0.3556)
		(layer "B.Cu")
		(net "GND")
	)
	(segment
		(start 386.192014 -271.500854)
		(end 386.206746 -271.50949)
		(width 0.0889)
		(layer "B.Cu")
		(net "GND")
	)
	(segment
		(start 287.672018 -319.925192)
		(end 287.384236 -319.63741)
		(width 0.3048)
		(layer "B.Cu")
		(net "GND")
	)
	(segment
		(start 191.280796 -18.938748)
		(end 191.571626 -19.229578)
		(width 0.3556)
		(layer "B.Cu")
		(net "GND")
	)
	(segment
		(start 433.50688 -178.755548)
		(end 433.297584 -178.964844)
		(width 0.3556)
		(layer "B.Cu")
		(net "GND")
	)
	(segment
		(start 387.103874 -190.223648)
		(end 386.906262 -190.42126)
		(width 0.3556)
		(layer "B.Cu")
		(net "GND")
	)
	(segment
		(start 130.814064 -270.695674)
		(end 130.828796 -270.687038)
		(width 0.0889)
		(layer "B.Cu")
		(net "GND")
	)
	(segment
		(start 307.782214 -317.166752)
		(end 307.521864 -316.906402)
		(width 0.3556)
		(layer "B.Cu")
		(net "GND")
	)
	(segment
		(start 156.41828 -119.421148)
		(end 156.62783 -119.211598)
		(width 0.3556)
		(layer "B.Cu")
		(net "GND")
	)
	(segment
		(start 252.320298 -108.977684)
		(end 252.718824 -108.579158)
		(width 0.381)
		(layer "B.Cu")
		(net "GND")
	)
	(segment
		(start 118.96344 -362.826808)
		(end 119.737632 -362.052616)
		(width 0.3556)
		(layer "B.Cu")
		(net "GND")
	)
	(segment
		(start 187.174886 -194.393058)
		(end 187.174886 -193.999866)
		(width 0.3556)
		(layer "B.Cu")
		(net "GND")
	)
	(segment
		(start 314.126626 -230.50119)
		(end 314.884308 -230.50119)
		(width 0.3556)
		(layer "B.Cu")
		(net "GND")
	)
	(segment
		(start 431.98034 -49.78654)
		(end 432.83378 -48.9331)
		(width 0.3556)
		(layer "B.Cu")
		(net "GND")
	)
	(segment
		(start 173.755558 -105.375456)
		(end 173.755558 -105.23855)
		(width 0.3556)
		(layer "B.Cu")
		(net "GND")
	)
	(segment
		(start 203.7842 -193.005202)
		(end 203.7842 -193.984118)
		(width 0.3556)
		(layer "B.Cu")
		(net "GND")
	)
	(segment
		(start 137.029444 -271.011396)
		(end 137.029444 -271.02689)
		(width 0.0889)
		(layer "B.Cu")
		(net "GND")
	)
	(segment
		(start 62.242446 -15.369794)
		(end 62.0522 -15.179548)
		(width 0.3556)
		(layer "B.Cu")
		(net "GND")
	)
	(segment
		(start 121.382028 -355.194108)
		(end 121.11736 -355.194108)
		(width 0.3556)
		(layer "B.Cu")
		(net "GND")
	)
	(segment
		(start 52.894738 -335.477612)
		(end 53.835046 -335.477612)
		(width 0.508)
		(layer "B.Cu")
		(net "GND")
	)
	(segment
		(start 144.91716 -28.989528)
		(end 144.91716 -27.859228)
		(width 0.254)
		(layer "B.Cu")
		(net "GND")
	)
	(segment
		(start 144.737328 -30.14218)
		(end 144.91716 -29.962348)
		(width 0.254)
		(layer "B.Cu")
		(net "GND")
	)
	(segment
		(start 431.22215 -52.10048)
		(end 431.22215 -51.42738)
		(width 0.3556)
		(layer "B.Cu")
		(net "GND")
	)
	(segment
		(start 120.3706 -379.517148)
		(end 120.3706 -367.802668)
		(width 0.3556)
		(layer "B.Cu")
		(net "GND")
	)
	(segment
		(start 72.82688 -10.468864)
		(end 72.82688 -10.867898)
		(width 0.3556)
		(layer "B.Cu")
		(net "GND")
	)
	(segment
		(start 174.984664 -319.268856)
		(end 175.009556 -319.293748)
		(width 0.3556)
		(layer "B.Cu")
		(net "GND")
	)
	(segment
		(start 318.215264 -36.439348)
		(end 319.047622 -36.439348)
		(width 0.3556)
		(layer "B.Cu")
		(net "GND")
	)
	(segment
		(start 374.821196 -186.858148)
		(end 375.578624 -187.615576)
		(width 0.3556)
		(layer "B.Cu")
		(net "GND")
	)
	(segment
		(start 235.488988 -421.99052)
		(end 235.23448 -422.245028)
		(width 0.3556)
		(layer "B.Cu")
		(net "GND")
	)
	(segment
		(start 179.542948 -107.1626)
		(end 179.35575 -106.975402)
		(width 0.3556)
		(layer "B.Cu")
		(net "GND")
	)
	(segment
		(start 147.96262 -188.857128)
		(end 147.96262 -189.641988)
		(width 0.3556)
		(layer "B.Cu")
		(net "GND")
	)
	(segment
		(start 51.95443 -335.477612)
		(end 52.894738 -335.477612)
		(width 0.508)
		(layer "B.Cu")
		(net "GND")
	)
	(segment
		(start 198.305674 -75.242674)
		(end 200.146158 -75.242674)
		(width 0.3556)
		(layer "B.Cu")
		(net "GND")
	)
	(segment
		(start 265.081766 -95.269812)
		(end 265.081766 -94.634812)
		(width 0.3556)
		(layer "B.Cu")
		(net "GND")
	)
	(segment
		(start 118.96344 -366.395508)
		(end 118.96344 -362.826808)
		(width 0.3556)
		(layer "B.Cu")
		(net "GND")
	)
	(segment
		(start 137.82548 -27.148028)
		(end 138.907012 -28.22956)
		(width 0.254)
		(layer "B.Cu")
		(net "GND")
	)
	(segment
		(start 433.832 -24.494998)
		(end 433.832 -25.176988)
		(width 0.3556)
		(layer "B.Cu")
		(net "GND")
	)
	(segment
		(start 162.8521 -354.620068)
		(end 162.8521 -379.628908)
		(width 0.3556)
		(layer "B.Cu")
		(net "GND")
	)
	(segment
		(start 174.018702 -104.975406)
		(end 174.155608 -104.975406)
		(width 0.3556)
		(layer "B.Cu")
		(net "GND")
	)
	(segment
		(start 435.518306 -46.154594)
		(end 435.518306 -47.03318)
		(width 0.3556)
		(layer "B.Cu")
		(net "GND")
	)
	(segment
		(start 61.326268 -319.393824)
		(end 61.996066 -320.063622)
		(width 0.381)
		(layer "B.Cu")
		(net "GND")
	)
	(segment
		(start 39.36111 -319.268856)
		(end 39.40429 -319.312036)
		(width 0.381)
		(layer "B.Cu")
		(net "GND")
	)
	(segment
		(start 183.907938 -104.975406)
		(end 183.755538 -104.975406)
		(width 0.3556)
		(layer "B.Cu")
		(net "GND")
	)
	(segment
		(start 349.764604 -356.397052)
		(end 349.764604 -357.239316)
		(width 0.381)
		(layer "B.Cu")
		(net "GND")
	)
	(segment
		(start 9.258046 -319.344548)
		(end 9.59358 -319.009014)
		(width 0.3556)
		(layer "B.Cu")
		(net "GND")
	)
	(segment
		(start 387.45668 -271.633188)
		(end 399.49628 -271.633188)
		(width 0.3556)
		(layer "B.Cu")
		(net "GND")
	)
	(segment
		(start 420.285418 -193.983356)
		(end 420.285418 -193.753486)
		(width 0.3556)
		(layer "B.Cu")
		(net "GND")
	)
	(segment
		(start 369.89893 -41.112948)
		(end 370.51488 -41.112948)
		(width 0.3556)
		(layer "B.Cu")
		(net "GND")
	)
	(segment
		(start 18.15211 -193.843656)
		(end 18.76171 -193.843656)
		(width 0.3556)
		(layer "B.Cu")
		(net "GND")
	)
	(segment
		(start 190.63335 -319.232788)
		(end 190.64859 -319.217548)
		(width 0.3556)
		(layer "B.Cu")
		(net "GND")
	)
	(segment
		(start 62.702186 -15.369794)
		(end 62.242446 -15.369794)
		(width 0.3556)
		(layer "B.Cu")
		(net "GND")
	)
	(segment
		(start 181.882796 -319.294256)
		(end 182.637684 -319.294256)
		(width 0.381)
		(layer "B.Cu")
		(net "GND")
	)
	(segment
		(start 457.0349 -49.476406)
		(end 457.732638 -50.174144)
		(width 0.508)
		(layer "B.Cu")
		(net "GND")
	)
	(segment
		(start 311.44083 -52.288948)
		(end 310.82488 -52.288948)
		(width 0.3556)
		(layer "B.Cu")
		(net "GND")
	)
	(segment
		(start 259.77469 -50.823876)
		(end 259.77469 -49.430686)
		(width 0.3556)
		(layer "B.Cu")
		(net "GND")
	)
	(segment
		(start 89.99347 -181.281578)
		(end 89.99347 -180.500528)
		(width 0.3556)
		(layer "B.Cu")
		(net "GND")
	)
	(segment
		(start 190.63335 -319.268348)
		(end 190.63335 -319.232788)
		(width 0.3556)
		(layer "B.Cu")
		(net "GND")
	)
	(segment
		(start 333.510382 -44.221146)
		(end 333.386938 -44.34459)
		(width 0.381)
		(layer "B.Cu")
		(net "GND")
	)
	(segment
		(start 429.797464 -319.263776)
		(end 430.547272 -319.263776)
		(width 0.3556)
		(layer "B.Cu")
		(net "GND")
	)
	(segment
		(start 403.43582 -337.558888)
		(end 406.70226 -340.825328)
		(width 0.3556)
		(layer "B.Cu")
		(net "GND")
	)
	(segment
		(start 161.090102 -319.704466)
		(end 160.952942 -319.567306)
		(width 0.381)
		(layer "B.Cu")
		(net "GND")
	)
	(segment
		(start 198.276718 -75.27163)
		(end 198.305674 -75.242674)
		(width 0.3556)
		(layer "B.Cu")
		(net "GND")
	)
	(segment
		(start 201.39533 -68.953126)
		(end 202.550522 -68.953126)
		(width 0.3556)
		(layer "B.Cu")
		(net "GND")
	)
	(segment
		(start 386.906262 -190.42126)
		(end 386.58165 -190.42126)
		(width 0.3556)
		(layer "B.Cu")
		(net "GND")
	)
	(segment
		(start 167.346884 -319.268856)
		(end 166.769796 -319.268856)
		(width 0.381)
		(layer "B.Cu")
		(net "GND")
	)
	(segment
		(start 453.450706 -319.179702)
		(end 453.450706 -318.704976)
		(width 0.3556)
		(layer "B.Cu")
		(net "GND")
	)
	(segment
		(start 46.697138 -335.477612)
		(end 47.637446 -335.477612)
		(width 0.508)
		(layer "B.Cu")
		(net "GND")
	)
	(segment
		(start 368.832638 -190.39713)
		(end 369.388898 -189.84087)
		(width 0.3556)
		(layer "B.Cu")
		(net "GND")
	)
	(segment
		(start 191.296798 -194.72275)
		(end 191.264286 -194.690238)
		(width 0.3556)
		(layer "B.Cu")
		(net "GND")
	)
	(segment
		(start 26.63825 -130.396996)
		(end 25.946608 -130.396996)
		(width 0.381)
		(layer "B.Cu")
		(net "GND")
	)
	(segment
		(start 62.176406 -319.464182)
		(end 62.246764 -319.393824)
		(width 0.3556)
		(layer "B.Cu")
		(net "GND")
	)
	(segment
		(start 7.79272 -112.04702)
		(end 7.79272 -111.288068)
		(width 0.3556)
		(layer "B.Cu")
		(net "GND")
	)
	(segment
		(start 449.5546 -8.772652)
		(end 449.5546 -9.583928)
		(width 0.3556)
		(layer "B.Cu")
		(net "GND")
	)
	(segment
		(start 287.775142 -320.004948)
		(end 287.695386 -319.925192)
		(width 0.3048)
		(layer "B.Cu")
		(net "GND")
	)
	(segment
		(start 14.899132 -191.55283)
		(end 14.727174 -191.724788)
		(width 0.3556)
		(layer "B.Cu")
		(net "GND")
	)
	(segment
		(start 374.055132 -270.695674)
		(end 374.069864 -270.687038)
		(width 0.0889)
		(layer "B.Cu")
		(net "GND")
	)
	(segment
		(start 214.155782 -93.004132)
		(end 216.254584 -93.881956)
		(width 0.254)
		(layer "B.Cu")
		(net "GND")
	)
	(segment
		(start 171.207684 -319.014856)
		(end 171.193968 -319.014856)
		(width 0.381)
		(layer "B.Cu")
		(net "GND")
	)
	(segment
		(start 218.2114 -193.46799)
		(end 217.090498 -193.46799)
		(width 0.3556)
		(layer "B.Cu")
		(net "GND")
	)
	(segment
		(start 88.693498 -182.400448)
		(end 88.693498 -181.73319)
		(width 0.3556)
		(layer "B.Cu")
		(net "GND")
	)
	(segment
		(start 207.059022 -193.37401)
		(end 207.955896 -193.37401)
		(width 0.3556)
		(layer "B.Cu")
		(net "GND")
	)
	(segment
		(start 125.175264 -270.695674)
		(end 125.189996 -270.687038)
		(width 0.0889)
		(layer "B.Cu")
		(net "GND")
	)
	(segment
		(start 139.004548 -271.450054)
		(end 139.293854 -271.450054)
		(width 0.0889)
		(layer "B.Cu")
		(net "GND")
	)
	(segment
		(start 369.89893 -46.192948)
		(end 370.51488 -46.192948)
		(width 0.3556)
		(layer "B.Cu")
		(net "GND")
	)
	(segment
		(start 174.80788 -98.643948)
		(end 174.814738 -98.63709)
		(width 0.3556)
		(layer "B.Cu")
		(net "GND")
	)
	(segment
		(start 286.359092 -344.700352)
		(end 287.2994 -344.700352)
		(width 0.508)
		(layer "B.Cu")
		(net "GND")
	)
	(segment
		(start 235.23448 -422.245028)
		(end 235.23448 -422.601898)
		(width 0.3556)
		(layer "B.Cu")
		(net "GND")
	)
	(segment
		(start 444.966344 -319.345056)
		(end 445.639952 -319.345056)
		(width 0.3556)
		(layer "B.Cu")
		(net "GND")
	)
	(segment
		(start 148.967698 -189.35065)
		(end 148.699474 -189.618874)
		(width 0.3556)
		(layer "B.Cu")
		(net "GND")
	)
	(segment
		(start 328.913998 -190.34506)
		(end 328.913998 -189.72911)
		(width 0.381)
		(layer "B.Cu")
		(net "GND")
	)
	(segment
		(start 198.264018 -109.89691)
		(end 197.837552 -109.89691)
		(width 0.3556)
		(layer "B.Cu")
		(net "GND")
	)
	(segment
		(start 182.611776 -319.268348)
		(end 182.611776 -318.352424)
		(width 0.381)
		(layer "B.Cu")
		(net "GND")
	)
	(segment
		(start 164.24783 -121.376948)
		(end 164.24783 -122.646948)
		(width 0.3556)
		(layer "B.Cu")
		(net "GND")
	)
	(segment
		(start 154.51836 -272.793968)
		(end 155.14828 -273.423888)
		(width 0.3556)
		(layer "B.Cu")
		(net "GND")
	)
	(segment
		(start 212.032596 -319.268856)
		(end 212.812884 -319.268856)
		(width 0.381)
		(layer "B.Cu")
		(net "GND")
	)
	(segment
		(start 144.91716 -27.859228)
		(end 144.90192 -27.843988)
		(width 0.254)
		(layer "B.Cu")
		(net "GND")
	)
	(segment
		(start 234.523788 -251.517658)
		(end 233.761788 -252.279658)
		(width 0.3556)
		(layer "B.Cu")
		(net "GND")
	)
	(segment
		(start 189.621922 -319.268856)
		(end 190.063882 -319.268856)
		(width 0.381)
		(layer "B.Cu")
		(net "GND")
	)
	(segment
		(start 449.526914 -8.744966)
		(end 449.5546 -8.772652)
		(width 0.3556)
		(layer "B.Cu")
		(net "GND")
	)
	(segment
		(start 123.617736 -359.764584)
		(end 124.09678 -359.764584)
		(width 0.3556)
		(layer "B.Cu")
		(net "GND")
	)
	(segment
		(start 224.401888 -97.25914)
		(end 225.518726 -98.200972)
		(width 0.254)
		(layer "B.Cu")
		(net "GND")
	)
	(segment
		(start 159.84728 -118.811548)
		(end 159.84728 -118.354348)
		(width 0.3556)
		(layer "B.Cu")
		(net "GND")
	)
	(segment
		(start 449.841366 -75.530456)
		(end 449.723764 -75.648058)
		(width 0.3556)
		(layer "B.Cu")
		(net "GND")
	)
	(segment
		(start 438.045352 -319.319656)
		(end 438.286906 -319.078102)
		(width 0.3556)
		(layer "B.Cu")
		(net "GND")
	)
	(segment
		(start 196.930518 -194.06235)
		(end 196.930518 -192.97015)
		(width 0.3556)
		(layer "B.Cu")
		(net "GND")
	)
	(segment
		(start 293.497 -343.760044)
		(end 293.497 -344.700352)
		(width 0.508)
		(layer "B.Cu")
		(net "GND")
	)
	(segment
		(start 435.48808 -9.439148)
		(end 435.145942 -9.09701)
		(width 0.3556)
		(layer "B.Cu")
		(net "GND")
	)
	(segment
		(start 159.766508 -42.205148)
		(end 158.718504 -42.205148)
		(width 0.3556)
		(layer "B.Cu")
		(net "GND")
	)
	(segment
		(start 186.155838 -109.628686)
		(end 186.155838 -109.775498)
		(width 0.3556)
		(layer "B.Cu")
		(net "GND")
	)
	(segment
		(start 184.555638 -113.77549)
		(end 184.955688 -114.17554)
		(width 0.3556)
		(layer "B.Cu")
		(net "GND")
	)
	(segment
		(start 54.565296 -319.712594)
		(end 54.880002 -319.397888)
		(width 0.381)
		(layer "B.Cu")
		(net "GND")
	)
	(segment
		(start 369.89893 -45.176948)
		(end 370.51488 -45.176948)
		(width 0.3556)
		(layer "B.Cu")
		(net "GND")
	)
	(segment
		(start 339.061044 -31.529528)
		(end 339.58022 -31.529528)
		(width 0.3556)
		(layer "B.Cu")
		(net "GND")
	)
	(segment
		(start 155.14828 -273.423888)
		(end 155.14828 -333.393288)
		(width 0.3556)
		(layer "B.Cu")
		(net "GND")
	)
	(segment
		(start 191.264286 -194.690238)
		(end 191.264286 -194.015106)
		(width 0.3556)
		(layer "B.Cu")
		(net "GND")
	)
	(segment
		(start 334.13192 -49.607216)
		(end 334.13192 -49.087278)
		(width 0.381)
		(layer "B.Cu")
		(net "GND")
	)
	(segment
		(start 132.693664 -270.695674)
		(end 132.708396 -270.687038)
		(width 0.0889)
		(layer "B.Cu")
		(net "GND")
	)
	(segment
		(start 32.157162 -319.001394)
		(end 32.157162 -318.650112)
		(width 0.381)
		(layer "B.Cu")
		(net "GND")
	)
	(segment
		(start 136.841992 -270.687038)
		(end 136.850882 -270.692118)
		(width 0.0889)
		(layer "B.Cu")
		(net "GND")
	)
	(segment
		(start 133.5786 -29.02585)
		(end 134.2136 -29.02585)
		(width 0.3556)
		(layer "B.Cu")
		(net "GND")
	)
	(segment
		(start 161.57956 -353.347528)
		(end 162.8521 -354.620068)
		(width 0.3556)
		(layer "B.Cu")
		(net "GND")
	)
	(segment
		(start 62.176406 -320.063622)
		(end 62.176406 -319.464182)
		(width 0.3556)
		(layer "B.Cu")
		(net "GND")
	)
	(segment
		(start 405.301958 -195.27012)
		(end 404.09241 -195.27012)
		(width 0.3556)
		(layer "B.Cu")
		(net "GND")
	)
	(segment
		(start 76.054458 -195.13931)
		(end 75.071478 -196.12229)
		(width 0.3556)
		(layer "B.Cu")
		(net "GND")
	)
	(segment
		(start 235.485178 -51.209448)
		(end 235.8009 -51.209448)
		(width 0.3556)
		(layer "B.Cu")
		(net "GND")
	)
	(segment
		(start 46.970442 -319.753234)
		(end 47.289466 -319.43421)
		(width 0.381)
		(layer "B.Cu")
		(net "GND")
	)
	(segment
		(start 449.723764 -75.648058)
		(end 449.723764 -76.297536)
		(width 0.3556)
		(layer "B.Cu")
		(net "GND")
	)
	(segment
		(start 414.709864 -319.263776)
		(end 415.281872 -319.263776)
		(width 0.3556)
		(layer "B.Cu")
		(net "GND")
	)
	(segment
		(start 340.17712 -31.9659)
		(end 339.740748 -31.529528)
		(width 0.3556)
		(layer "B.Cu")
		(net "GND")
	)
	(segment
		(start 178.1556 -118.575328)
		(end 177.75555 -118.975378)
		(width 0.3556)
		(layer "B.Cu")
		(net "GND")
	)
	(segment
		(start 244.82552 -100.121212)
		(end 245.435374 -100.121212)
		(width 0.381)
		(layer "B.Cu")
		(net "GND")
	)
	(segment
		(start 95.14586 -187.179712)
		(end 96.241108 -188.27496)
		(width 0.3556)
		(layer "B.Cu")
		(net "GND")
	)
	(segment
		(start 448.828922 -48.778668)
		(end 449.52666 -49.476406)
		(width 0.508)
		(layer "B.Cu")
		(net "GND")
	)
	(segment
		(start 365.42599 -399.914618)
		(end 365.42599 -398.976088)
		(width 0.3556)
		(layer "B.Cu")
		(net "GND")
	)
	(segment
		(start 343.55024 -52.209446)
		(end 343.157302 -52.602384)
		(width 0.3556)
		(layer "B.Cu")
		(net "GND")
	)
	(segment
		(start 120.910604 -362.052616)
		(end 121.830084 -361.133136)
		(width 0.3556)
		(layer "B.Cu")
		(net "GND")
	)
	(segment
		(start 212.559138 -193.67373)
		(end 212.802978 -193.42989)
		(width 0.3556)
		(layer "B.Cu")
		(net "GND")
	)
	(segment
		(start 230.156258 -126.071122)
		(end 229.87254 -125.787404)
		(width 0.3556)
		(layer "B.Cu")
		(net "GND")
	)
	(segment
		(start 127.83566 -36.359338)
		(end 127.83566 -35.684968)
		(width 0.3556)
		(layer "B.Cu")
		(net "GND")
	)
	(segment
		(start 192.395856 -72.804528)
		(end 191.58966 -72.804528)
		(width 0.3556)
		(layer "B.Cu")
		(net "GND")
	)
	(segment
		(start 24.672798 -319.017396)
		(end 24.672798 -318.633856)
		(width 0.381)
		(layer "B.Cu")
		(net "GND")
	)
	(segment
		(start 320.645282 -26.31059)
		(end 320.645282 -25.785318)
		(width 0.3556)
		(layer "B.Cu")
		(net "GND")
	)
	(segment
		(start 212.802978 -193.42989)
		(end 213.612476 -193.42989)
		(width 0.3556)
		(layer "B.Cu")
		(net "GND")
	)
	(segment
		(start 171.193968 -319.014856)
		(end 171.18584 -319.006728)
		(width 0.381)
		(layer "B.Cu")
		(net "GND")
	)
	(segment
		(start 272.204942 -319.263776)
		(end 272.285714 -319.344548)
		(width 0.254)
		(layer "B.Cu")
		(net "GND")
	)
	(segment
		(start 339.391498 -191.93129)
		(end 339.759798 -191.56299)
		(width 0.3556)
		(layer "B.Cu")
		(net "GND")
	)
	(segment
		(start 75.87488 -10.867898)
		(end 75.87488 -10.164318)
		(width 0.3556)
		(layer "B.Cu")
		(net "GND")
	)
	(segment
		(start 252.05563 -106.23804)
		(end 252.05563 -105.656634)
		(width 0.381)
		(layer "B.Cu")
		(net "GND")
	)
	(segment
		(start 369.388898 -188.07049)
		(end 369.388898 -189.84087)
		(width 0.3556)
		(layer "B.Cu")
		(net "GND")
	)
	(segment
		(start 31.819596 -319.268856)
		(end 31.854648 -319.303908)
		(width 0.381)
		(layer "B.Cu")
		(net "GND")
	)
	(segment
		(start 330.315316 -24.206708)
		(end 330.69403 -24.585422)
		(width 0.3556)
		(layer "B.Cu")
		(net "GND")
	)
	(segment
		(start 369.89893 -43.144948)
		(end 370.51488 -43.144948)
		(width 0.3556)
		(layer "B.Cu")
		(net "GND")
	)
	(segment
		(start 197.686422 -319.331594)
		(end 197.686422 -318.332358)
		(width 0.381)
		(layer "B.Cu")
		(net "GND")
	)
	(segment
		(start 449.723764 -76.297536)
		(end 450.710808 -76.297536)
		(width 0.3556)
		(layer "B.Cu")
		(net "GND")
	)
	(segment
		(start 33.924494 -193.324226)
		(end 34.551366 -193.324226)
		(width 0.3556)
		(layer "B.Cu")
		(net "GND")
	)
	(segment
		(start 255.224534 -107.361228)
		(end 255.841246 -107.361228)
		(width 0.381)
		(layer "B.Cu")
		(net "GND")
	)
	(segment
		(start 250.744736 -86.992714)
		(end 250.744736 -86.816946)
		(width 0.3556)
		(layer "B.Cu")
		(net "GND")
	)
	(segment
		(start 16.2941 -110.482888)
		(end 16.189452 -110.587536)
		(width 0.3556)
		(layer "B.Cu")
		(net "GND")
	)
	(segment
		(start 39.221156 -318.733678)
		(end 39.36111 -318.873632)
		(width 0.3556)
		(layer "B.Cu")
		(net "GND")
	)
	(segment
		(start 272.549366 -319.080896)
		(end 272.549366 -318.644016)
		(width 0.254)
		(layer "B.Cu")
		(net "GND")
	)
	(segment
		(start 28.216098 -132.093208)
		(end 28.574238 -131.735068)
		(width 0.381)
		(layer "B.Cu")
		(net "GND")
	)
	(segment
		(start 320.297048 -37.159946)
		(end 320.493136 -37.159946)
		(width 0.3556)
		(layer "B.Cu")
		(net "GND")
	)
	(segment
		(start 371.189758 -360.132376)
		(end 372.070122 -360.132376)
		(width 0.3556)
		(layer "B.Cu")
		(net "GND")
	)
	(segment
		(start 187.604146 -104.823768)
		(end 188.06541 -104.823768)
		(width 0.3556)
		(layer "B.Cu")
		(net "GND")
	)
	(segment
		(start 133.027674 -366.445546)
		(end 133.725412 -365.747808)
		(width 0.508)
		(layer "B.Cu")
		(net "GND")
	)
	(segment
		(start 174.814738 -98.63709)
		(end 174.814738 -97.72142)
		(width 0.3556)
		(layer "B.Cu")
		(net "GND")
	)
	(segment
		(start 431.24374 -129.191258)
		(end 431.5841 -129.191258)
		(width 0.3556)
		(layer "B.Cu")
		(net "GND")
	)
	(segment
		(start 404.92172 -382.288288)
		(end 369.56238 -382.288288)
		(width 0.3556)
		(layer "B.Cu")
		(net "GND")
	)
	(segment
		(start 40.506396 -335.471262)
		(end 41.446704 -335.471262)
		(width 0.508)
		(layer "B.Cu")
		(net "GND")
	)
	(segment
		(start 178.520852 -104.71277)
		(end 178.520852 -105.340658)
		(width 0.3556)
		(layer "B.Cu")
		(net "GND")
	)
	(segment
		(start 196.944996 -319.268856)
		(end 197.420484 -319.268856)
		(width 0.381)
		(layer "B.Cu")
		(net "GND")
	)
	(segment
		(start 432.523392 -193.965322)
		(end 433.564792 -193.965322)
		(width 0.3556)
		(layer "B.Cu")
		(net "GND")
	)
	(segment
		(start 369.744498 -187.71489)
		(end 369.388898 -188.07049)
		(width 0.3556)
		(layer "B.Cu")
		(net "GND")
	)
	(segment
		(start 316.822582 -30.987746)
		(end 317.358014 -31.523178)
		(width 0.3556)
		(layer "B.Cu")
		(net "GND")
	)
	(segment
		(start 182.337964 -335.483962)
		(end 183.353964 -335.483962)
		(width 0.508)
		(layer "B.Cu")
		(net "GND")
	)
	(segment
		(start 453.183752 -319.446656)
		(end 453.450706 -319.179702)
		(width 0.3556)
		(layer "B.Cu")
		(net "GND")
	)
	(segment
		(start 378.754132 -270.695674)
		(end 378.768864 -270.687038)
		(width 0.0889)
		(layer "B.Cu")
		(net "GND")
	)
	(segment
		(start 264.752074 -319.401952)
		(end 265.006328 -319.147698)
		(width 0.381)
		(layer "B.Cu")
		(net "GND")
	)
	(segment
		(start 185.755788 -117.375432)
		(end 185.898536 -117.375432)
		(width 0.3556)
		(layer "B.Cu")
		(net "GND")
	)
	(segment
		(start 251.90958 -106.38409)
		(end 252.05563 -106.23804)
		(width 0.381)
		(layer "B.Cu")
		(net "GND")
	)
	(segment
		(start 268.829282 -194.766692)
		(end 268.668246 -194.605656)
		(width 0.3048)
		(layer "B.Cu")
		(net "GND")
	)
	(segment
		(start 144.91716 -29.962348)
		(end 144.91716 -28.989528)
		(width 0.254)
		(layer "B.Cu")
		(net "GND")
	)
	(segment
		(start 319.446402 -36.838128)
		(end 319.97523 -36.838128)
		(width 0.3556)
		(layer "B.Cu")
		(net "GND")
	)
	(segment
		(start 366.738662 -271.011396)
		(end 367.462054 -270.704056)
		(width 0.0889)
		(layer "B.Cu")
		(net "GND")
	)
	(segment
		(start 212.754972 -195.58635)
		(end 213.441788 -195.58635)
		(width 0.3556)
		(layer "B.Cu")
		(net "GND")
	)
	(segment
		(start 68.29298 -188.381386)
		(end 68.29298 -188.974222)
		(width 0.3556)
		(layer "B.Cu")
		(net "GND")
	)
	(segment
		(start 309.100982 -319.224406)
		(end 309.100982 -319.400174)
		(width 0.3556)
		(layer "B.Cu")
		(net "GND")
	)
	(segment
		(start 279.794716 -319.303908)
		(end 280.011632 -319.520824)
		(width 0.3556)
		(layer "B.Cu")
		(net "GND")
	)
	(segment
		(start 345.220798 -33.062672)
		(end 345.220798 -32.58439)
		(width 0.3556)
		(layer "B.Cu")
		(net "GND")
	)
	(segment
		(start 243.99748 -128.736598)
		(end 243.99748 -129.403348)
		(width 0.3556)
		(layer "B.Cu")
		(net "GND")
	)
	(segment
		(start 234.26928 -422.601898)
		(end 234.26928 -421.882062)
		(width 0.3556)
		(layer "B.Cu")
		(net "GND")
	)
	(segment
		(start 185.9026 -109.375448)
		(end 186.155838 -109.628686)
		(width 0.3556)
		(layer "B.Cu")
		(net "GND")
	)
	(segment
		(start 205.243684 -318.956944)
		(end 205.170532 -318.883792)
		(width 0.381)
		(layer "B.Cu")
		(net "GND")
	)
	(segment
		(start 231.57688 -129.962148)
		(end 232.580434 -129.962148)
		(width 0.381)
		(layer "B.Cu")
		(net "GND")
	)
	(segment
		(start 160.3502 -42.639488)
		(end 159.91586 -42.205148)
		(width 0.3556)
		(layer "B.Cu")
		(net "GND")
	)
	(segment
		(start 91.42222 -186.17819)
		(end 94.144338 -186.17819)
		(width 0.3556)
		(layer "B.Cu")
		(net "GND")
	)
	(segment
		(start 381.750824 -365.64062)
		(end 382.741424 -365.64062)
		(width 0.508)
		(layer "B.Cu")
		(net "GND")
	)
	(segment
		(start 126.65202 -36.361878)
		(end 126.65202 -35.684968)
		(width 0.3556)
		(layer "B.Cu")
		(net "GND")
	)
	(segment
		(start 133.725412 -365.747808)
		(end 134.42315 -366.445546)
		(width 0.508)
		(layer "B.Cu")
		(net "GND")
	)
	(segment
		(start 380.633732 -270.695674)
		(end 380.648464 -270.687038)
		(width 0.0889)
		(layer "B.Cu")
		(net "GND")
	)
	(segment
		(start 236.22508 -48.104044)
		(end 235.491782 -48.104044)
		(width 0.3556)
		(layer "B.Cu")
		(net "GND")
	)
	(segment
		(start 19.588734 -177.415952)
		(end 19.588734 -176.823624)
		(width 0.3556)
		(layer "B.Cu")
		(net "GND")
	)
	(segment
		(start 122.360436 -270.693134)
		(end 122.37085 -270.687038)
		(width 0.0889)
		(layer "B.Cu")
		(net "GND")
	)
	(segment
		(start 182.275988 -104.716326)
		(end 182.275988 -103.72979)
		(width 0.3556)
		(layer "B.Cu")
		(net "GND")
	)
	(segment
		(start 190.063882 -319.268856)
		(end 190.096902 -319.301876)
		(width 0.3556)
		(layer "B.Cu")
		(net "GND")
	)
	(segment
		(start 295.086278 -319.577466)
		(end 295.628314 -319.577466)
		(width 0.3556)
		(layer "B.Cu")
		(net "GND")
	)
	(segment
		(start 156.045408 -194.95516)
		(end 156.1465 -194.95516)
		(width 0.3556)
		(layer "B.Cu")
		(net "GND")
	)
	(segment
		(start 183.353964 -335.483962)
		(end 184.369964 -335.483962)
		(width 0.508)
		(layer "B.Cu")
		(net "GND")
	)
	(segment
		(start 128.85674 -20.206208)
		(end 128.85674 -20.596098)
		(width 0.3556)
		(layer "B.Cu")
		(net "GND")
	)
	(segment
		(start 183.888634 -121.775474)
		(end 183.755538 -121.775474)
		(width 0.3556)
		(layer "B.Cu")
		(net "GND")
	)
	(segment
		(start 311.427622 -38.809168)
		(end 312.132472 -38.809168)
		(width 0.3556)
		(layer "B.Cu")
		(net "GND")
	)
	(segment
		(start 292.980618 -149.592538)
		(end 292.980618 -148.961348)
		(width 0.3556)
		(layer "B.Cu")
		(net "GND")
	)
	(segment
		(start 155.14828 -120.106948)
		(end 155.83408 -119.421148)
		(width 0.3556)
		(layer "B.Cu")
		(net "GND")
	)
	(segment
		(start 385.46405 -190.42126)
		(end 386.58165 -190.42126)
		(width 0.3556)
		(layer "B.Cu")
		(net "GND")
	)
	(segment
		(start 184.155588 -105.223056)
		(end 183.907938 -104.975406)
		(width 0.3556)
		(layer "B.Cu")
		(net "GND")
	)
	(segment
		(start 257.51282 -319.001394)
		(end 257.51282 -318.582802)
		(width 0.3556)
		(layer "B.Cu")
		(net "GND")
	)
	(segment
		(start 284.446726 -194.236848)
		(end 284.446726 -194.091306)
		(width 0.3556)
		(layer "B.Cu")
		(net "GND")
	)
	(segment
		(start 419.502082 -194.766692)
		(end 420.285418 -193.983356)
		(width 0.3556)
		(layer "B.Cu")
		(net "GND")
	)
	(segment
		(start 279.164796 -319.303908)
		(end 279.794716 -319.303908)
		(width 0.3556)
		(layer "B.Cu")
		(net "GND")
	)
	(segment
		(start 263.37641 -74.480928)
		(end 263.398 -74.502518)
		(width 0.3556)
		(layer "B.Cu")
		(net "GND")
	)
	(segment
		(start 124.235464 -270.695674)
		(end 124.250196 -270.687038)
		(width 0.0889)
		(layer "B.Cu")
		(net "GND")
	)
	(segment
		(start 157.111446 -319.65138)
		(end 157.399482 -319.363344)
		(width 0.3556)
		(layer "B.Cu")
		(net "GND")
	)
	(segment
		(start 445.779906 -319.205102)
		(end 445.779906 -318.603376)
		(width 0.3556)
		(layer "B.Cu")
		(net "GND")
	)
	(segment
		(start 204.873352 -89.178638)
		(end 206.71917 -89.918032)
		(width 0.254)
		(layer "B.Cu")
		(net "GND")
	)
	(segment
		(start 367.89868 -380.624588)
		(end 367.89868 -362.858304)
		(width 0.3556)
		(layer "B.Cu")
		(net "GND")
	)
	(segment
		(start 331.146912 -31.850838)
		(end 331.146912 -32.31261)
		(width 0.381)
		(layer "B.Cu")
		(net "GND")
	)
	(segment
		(start 133.027674 -365.05007)
		(end 133.725412 -365.747808)
		(width 0.508)
		(layer "B.Cu")
		(net "GND")
	)
	(segment
		(start 110.577376 -360.847386)
		(end 111.221266 -360.847386)
		(width 0.381)
		(layer "B.Cu")
		(net "GND")
	)
	(segment
		(start 209.370168 -193.171826)
		(end 209.370168 -193.09461)
		(width 0.3556)
		(layer "B.Cu")
		(net "GND")
	)
	(segment
		(start 427.490128 -344.017346)
		(end 428.430436 -344.017346)
		(width 0.508)
		(layer "B.Cu")
		(net "GND")
	)
	(segment
		(start 194.00393 -106.225848)
		(end 194.61353 -106.225848)
		(width 0.3556)
		(layer "B.Cu")
		(net "GND")
	)
	(segment
		(start 266.4714 -99.101148)
		(end 266.065 -98.694748)
		(width 0.3556)
		(layer "B.Cu")
		(net "GND")
	)
	(segment
		(start 127.054864 -270.695674)
		(end 127.069596 -270.687038)
		(width 0.0889)
		(layer "B.Cu")
		(net "GND")
	)
	(segment
		(start 6.2738 -194.4624)
		(end 6.2738 -195.6562)
		(width 0.3556)
		(layer "B.Cu")
		(net "GND")
	)
	(segment
		(start 175.009556 -319.293748)
		(end 175.57115 -319.293748)
		(width 0.3556)
		(layer "B.Cu")
		(net "GND")
	)
	(segment
		(start 400.8501 -272.987008)
		(end 402.65858 -272.987008)
		(width 0.3556)
		(layer "B.Cu")
		(net "GND")
	)
	(segment
		(start 408.9781 -319.321688)
		(end 408.9781 -318.93637)
		(width 0.3556)
		(layer "B.Cu")
		(net "GND")
	)
	(segment
		(start 187.273946 -194.789298)
		(end 187.273946 -194.492118)
		(width 0.3556)
		(layer "B.Cu")
		(net "GND")
	)
	(segment
		(start 127.994664 -270.695674)
		(end 128.009396 -270.687038)
		(width 0.0889)
		(layer "B.Cu")
		(net "GND")
	)
	(segment
		(start 160.7312 -335.415128)
		(end 161.57956 -336.263488)
		(width 0.3556)
		(layer "B.Cu")
		(net "GND")
	)
	(segment
		(start 387.22427 -190.223648)
		(end 387.103874 -190.223648)
		(width 0.3556)
		(layer "B.Cu")
		(net "GND")
	)
	(segment
		(start 364.387638 -183.78043)
		(end 364.387638 -184.051448)
		(width 0.3556)
		(layer "B.Cu")
		(net "GND")
	)
	(segment
		(start 184.155588 -121.50852)
		(end 183.888634 -121.775474)
		(width 0.3556)
		(layer "B.Cu")
		(net "GND")
	)
	(segment
		(start 266.065 -98.694748)
		(end 266.065 -98.408998)
		(width 0.3556)
		(layer "B.Cu")
		(net "GND")
	)
	(segment
		(start 407.0731 -318.680592)
		(end 407.938986 -318.680592)
		(width 0.3556)
		(layer "B.Cu")
		(net "GND")
	)
	(segment
		(start 449.5546 -9.583928)
		(end 449.19646 -9.583928)
		(width 0.3556)
		(layer "B.Cu")
		(net "GND")
	)
	(segment
		(start 137.82548 -26.251408)
		(end 137.82548 -27.148028)
		(width 0.254)
		(layer "B.Cu")
		(net "GND")
	)
	(segment
		(start 40.506396 -334.530954)
		(end 40.506396 -335.471262)
		(width 0.508)
		(layer "B.Cu")
		(net "GND")
	)
	(segment
		(start 185.898536 -117.375432)
		(end 186.155838 -117.11813)
		(width 0.3556)
		(layer "B.Cu")
		(net "GND")
	)
	(segment
		(start 371.673628 -189.56147)
		(end 371.673628 -190.01994)
		(width 0.3556)
		(layer "B.Cu")
		(net "GND")
	)
	(segment
		(start 236.22508 -49.069244)
		(end 236.22508 -48.104044)
		(width 0.3556)
		(layer "B.Cu")
		(net "GND")
	)
	(segment
		(start 433.328318 -176.75606)
		(end 432.325018 -176.75606)
		(width 0.3556)
		(layer "B.Cu")
		(net "GND")
	)
	(segment
		(start 23.640796 -319.268856)
		(end 24.269954 -319.268856)
		(width 0.381)
		(layer "B.Cu")
		(net "GND")
	)
	(segment
		(start 42.814748 -101.413818)
		(end 42.814748 -100.984812)
		(width 0.3556)
		(layer "B.Cu")
		(net "GND")
	)
	(segment
		(start 165.506908 -250.271534)
		(end 165.985952 -250.271534)
		(width 0.3556)
		(layer "B.Cu")
		(net "GND")
	)
	(segment
		(start 287.2994 -343.760044)
		(end 287.2994 -344.700352)
		(width 0.508)
		(layer "B.Cu")
		(net "GND")
	)
	(segment
		(start 177.156364 -335.483962)
		(end 178.172364 -335.483962)
		(width 0.508)
		(layer "B.Cu")
		(net "GND")
	)
	(segment
		(start 302.056546 -319.263776)
		(end 302.505364 -319.712594)
		(width 0.3556)
		(layer "B.Cu")
		(net "GND")
	)
	(segment
		(start 396.29207 -61.048138)
		(end 396.97406 -61.048138)
		(width 0.3556)
		(layer "B.Cu")
		(net "GND")
	)
	(segment
		(start 213.295484 -318.125602)
		(end 213.27745 -318.107568)
		(width 0.381)
		(layer "B.Cu")
		(net "GND")
	)
	(segment
		(start 422.512744 -319.522856)
		(end 423.084752 -319.522856)
		(width 0.3556)
		(layer "B.Cu")
		(net "GND")
	)
	(segment
		(start 319.047622 -36.439348)
		(end 319.446402 -36.838128)
		(width 0.3556)
		(layer "B.Cu")
		(net "GND")
	)
	(segment
		(start 341.253318 -52.480972)
		(end 341.921338 -53.148992)
		(width 0.381)
		(layer "B.Cu")
		(net "GND")
	)
	(segment
		(start 170.155616 -117.108478)
		(end 170.155616 -116.975382)
		(width 0.3556)
		(layer "B.Cu")
		(net "GND")
	)
	(segment
		(start 16.096996 -319.268856)
		(end 16.67891 -319.268856)
		(width 0.381)
		(layer "B.Cu")
		(net "GND")
	)
	(segment
		(start 363.029754 -358.544114)
		(end 363.029754 -358.675432)
		(width 0.381)
		(layer "B.Cu")
		(net "GND")
	)
	(segment
		(start 447.818764 -9.224264)
		(end 447.56705 -9.475978)
		(width 0.3556)
		(layer "B.Cu")
		(net "GND")
	)
	(segment
		(start 157.17012 -335.415128)
		(end 160.7312 -335.415128)
		(width 0.3556)
		(layer "B.Cu")
		(net "GND")
	)
	(segment
		(start 16.189452 -110.587536)
		(end 15.433294 -110.587536)
		(width 0.3556)
		(layer "B.Cu")
		(net "GND")
	)
	(segment
		(start 238.237522 -127.49022)
		(end 238.236252 -127.48895)
		(width 0.3556)
		(layer "B.Cu")
		(net "GND")
	)
	(segment
		(start 170.155616 -109.631226)
		(end 170.155616 -109.775498)
		(width 0.3556)
		(layer "B.Cu")
		(net "GND")
	)
	(segment
		(start 240.3094 -422.58615)
		(end 240.3094 -421.9194)
		(width 0.3556)
		(layer "B.Cu")
		(net "GND")
	)
	(segment
		(start 311.44083 -53.304948)
		(end 311.44083 -52.288948)
		(width 0.3556)
		(layer "B.Cu")
		(net "GND")
	)
	(segment
		(start 136.2075 -30.330648)
		(end 136.2075 -28.598368)
		(width 0.3556)
		(layer "B.Cu")
		(net "GND")
	)
	(segment
		(start 271.580864 -319.263776)
		(end 272.204942 -319.263776)
		(width 0.254)
		(layer "B.Cu")
		(net "GND")
	)
	(segment
		(start 263.064752 -99.850448)
		(end 263.064752 -100.243132)
		(width 0.3556)
		(layer "B.Cu")
		(net "GND")
	)
	(segment
		(start 203.477876 -79.444342)
		(end 202.84948 -79.444342)
		(width 0.3556)
		(layer "B.Cu")
		(net "GND")
	)
	(segment
		(start 367.378488 -189.56147)
		(end 367.378488 -189.92342)
		(width 0.3556)
		(layer "B.Cu")
		(net "GND")
	)
	(segment
		(start 447.56705 -9.475978)
		(end 447.56705 -10.194036)
		(width 0.3556)
		(layer "B.Cu")
		(net "GND")
	)
	(segment
		(start 248.943368 -105.656634)
		(end 248.943368 -107.007406)
		(width 0.381)
		(layer "B.Cu")
		(net "GND")
	)
	(segment
		(start 9.59358 -319.009014)
		(end 9.59358 -318.6176)
		(width 0.3556)
		(layer "B.Cu")
		(net "GND")
	)
	(segment
		(start 203.733908 -194.03441)
		(end 203.181458 -194.03441)
		(width 0.3556)
		(layer "B.Cu")
		(net "GND")
	)
	(segment
		(start 233.2482 -422.61155)
		(end 234.259628 -422.61155)
		(width 0.3556)
		(layer "B.Cu")
		(net "GND")
	)
	(segment
		(start 61.996066 -320.063622)
		(end 62.176406 -320.063622)
		(width 0.381)
		(layer "B.Cu")
		(net "GND")
	)
	(segment
		(start 374.994932 -270.695674)
		(end 375.009664 -270.687038)
		(width 0.0889)
		(layer "B.Cu")
		(net "GND")
	)
	(segment
		(start 149.857206 -189.35065)
		(end 148.967698 -189.35065)
		(width 0.3556)
		(layer "B.Cu")
		(net "GND")
	)
	(segment
		(start 372.070122 -360.132376)
		(end 372.299738 -359.90276)
		(width 0.3556)
		(layer "B.Cu")
		(net "GND")
	)
	(segment
		(start 24.269954 -319.268856)
		(end 24.345646 -319.344548)
		(width 0.381)
		(layer "B.Cu")
		(net "GND")
	)
	(segment
		(start 239.2934 -422.58615)
		(end 240.3094 -422.58615)
		(width 0.3556)
		(layer "B.Cu")
		(net "GND")
	)
	(segment
		(start 157.000956 -319.65138)
		(end 157.111446 -319.65138)
		(width 0.3556)
		(layer "B.Cu")
		(net "GND")
	)
	(segment
		(start 369.89893 -37.937948)
		(end 370.51488 -37.937948)
		(width 0.3556)
		(layer "B.Cu")
		(net "GND")
	)
	(segment
		(start 238.30788 -422.576498)
		(end 238.30788 -421.909748)
		(width 0.3556)
		(layer "B.Cu")
		(net "GND")
	)
	(segment
		(start 151.5491 -271.623028)
		(end 152.72004 -272.793968)
		(width 0.3556)
		(layer "B.Cu")
		(net "GND")
	)
	(segment
		(start 380.760224 -365.64062)
		(end 381.750824 -365.64062)
		(width 0.508)
		(layer "B.Cu")
		(net "GND")
	)
	(segment
		(start 382.513332 -270.695674)
		(end 382.528064 -270.687038)
		(width 0.0889)
		(layer "B.Cu")
		(net "GND")
	)
	(segment
		(start 257.030474 -319.48374)
		(end 257.185922 -319.328292)
		(width 0.3556)
		(layer "B.Cu")
		(net "GND")
	)
	(segment
		(start 309.47741 -319.776602)
		(end 309.66283 -319.85331)
		(width 0.3556)
		(layer "B.Cu")
		(net "GND")
	)
	(segment
		(start 348.879414 -355.919786)
		(end 348.879414 -356.192836)
		(width 0.381)
		(layer "B.Cu")
		(net "GND")
	)
	(segment
		(start 415.680906 -319.230502)
		(end 415.680906 -318.730376)
		(width 0.3556)
		(layer "B.Cu")
		(net "GND")
	)
	(segment
		(start 462.039716 -318.512444)
		(end 461.918812 -318.39154)
		(width 0.3556)
		(layer "B.Cu")
		(net "GND")
	)
	(segment
		(start 339.759798 -191.321436)
		(end 339.97773 -191.103504)
		(width 0.3556)
		(layer "B.Cu")
		(net "GND")
	)
	(segment
		(start 174.313596 -319.268856)
		(end 174.984664 -319.268856)
		(width 0.381)
		(layer "B.Cu")
		(net "GND")
	)
	(segment
		(start 88.693498 -181.73319)
		(end 89.541858 -181.73319)
		(width 0.3556)
		(layer "B.Cu")
		(net "GND")
	)
	(segment
		(start 337.889342 -32.606742)
		(end 337.552284 -32.9438)
		(width 0.3556)
		(layer "B.Cu")
		(net "GND")
	)
	(segment
		(start 365.042958 -183.12511)
		(end 364.387638 -183.78043)
		(width 0.3556)
		(layer "B.Cu")
		(net "GND")
	)
	(segment
		(start 94.144338 -186.17819)
		(end 95.14586 -187.179712)
		(width 0.3556)
		(layer "B.Cu")
		(net "GND")
	)
	(segment
		(start 299.6946 -344.700352)
		(end 300.634908 -344.700352)
		(width 0.508)
		(layer "B.Cu")
		(net "GND")
	)
	(segment
		(start 365.03356 -400.307048)
		(end 365.42599 -399.914618)
		(width 0.3556)
		(layer "B.Cu")
		(net "GND")
	)
	(segment
		(start 159.82188 -118.836948)
		(end 159.84728 -118.811548)
		(width 0.3556)
		(layer "B.Cu")
		(net "GND")
	)
	(segment
		(start 193.958718 -193.63436)
		(end 193.759328 -193.43497)
		(width 0.3556)
		(layer "B.Cu")
		(net "GND")
	)
	(segment
		(start 206.9592 -193.274188)
		(end 207.059022 -193.37401)
		(width 0.3556)
		(layer "B.Cu")
		(net "GND")
	)
	(segment
		(start 415.101786 -344.010996)
		(end 416.042094 -344.010996)
		(width 0.508)
		(layer "B.Cu")
		(net "GND")
	)
	(segment
		(start 71.167498 -206.38897)
		(end 70.012306 -207.544162)
		(width 0.3556)
		(layer "B.Cu")
		(net "GND")
	)
	(segment
		(start 267.652246 -193.903346)
		(end 268.668246 -193.903346)
		(width 0.3048)
		(layer "B.Cu")
		(net "GND")
	)
	(segment
		(start 449.19646 -9.583928)
		(end 448.836796 -9.224264)
		(width 0.3556)
		(layer "B.Cu")
		(net "GND")
	)
	(segment
		(start 309.906162 -319.85331)
		(end 310.116474 -320.063622)
		(width 0.3556)
		(layer "B.Cu")
		(net "GND")
	)
	(segment
		(start 259.064506 -76.991972)
		(end 259.097526 -76.958952)
		(width 0.381)
		(layer "B.Cu")
		(net "GND")
	)
	(segment
		(start 165.252146 -250.016772)
		(end 165.506908 -250.271534)
		(width 0.3556)
		(layer "B.Cu")
		(net "GND")
	)
	(segment
		(start 314.710572 -52.187348)
		(end 314.710572 -53.203348)
		(width 0.3556)
		(layer "B.Cu")
		(net "GND")
	)
	(segment
		(start 372.81993 -36.921948)
		(end 373.43588 -36.921948)
		(width 0.3556)
		(layer "B.Cu")
		(net "GND")
	)
	(segment
		(start 178.45024 -107.07116)
		(end 179.259992 -107.07116)
		(width 0.3556)
		(layer "B.Cu")
		(net "GND")
	)
	(segment
		(start 191.264286 -194.015106)
		(end 192.280286 -194.015106)
		(width 0.3556)
		(layer "B.Cu")
		(net "GND")
	)
	(segment
		(start 449.5546 -9.583928)
		(end 450.25818 -9.583928)
		(width 0.3556)
		(layer "B.Cu")
		(net "GND")
	)
	(segment
		(start 216.254584 -93.881956)
		(end 218.372436 -94.750128)
		(width 0.254)
		(layer "B.Cu")
		(net "GND")
	)
	(segment
		(start 449.52666 -49.476406)
		(end 450.224398 -50.174144)
		(width 0.508)
		(layer "B.Cu")
		(net "GND")
	)
	(segment
		(start 339.759798 -191.56299)
		(end 339.759798 -191.321436)
		(width 0.3556)
		(layer "B.Cu")
		(net "GND")
	)
	(segment
		(start 369.89893 -44.160948)
		(end 370.51488 -44.160948)
		(width 0.3556)
		(layer "B.Cu")
		(net "GND")
	)
	(segment
		(start 375.578624 -187.615576)
		(end 375.578624 -190.303404)
		(width 0.3556)
		(layer "B.Cu")
		(net "GND")
	)
	(segment
		(start 178.520852 -105.340658)
		(end 178.55565 -105.375456)
		(width 0.3556)
		(layer "B.Cu")
		(net "GND")
	)
	(segment
		(start 174.002446 -121.775474)
		(end 174.155608 -121.775474)
		(width 0.3556)
		(layer "B.Cu")
		(net "GND")
	)
	(segment
		(start 449.52666 -49.476406)
		(end 450.224398 -48.778668)
		(width 0.508)
		(layer "B.Cu")
		(net "GND")
	)
	(segment
		(start 262.392414 -101.595682)
		(end 262.392414 -100.91547)
		(width 0.3556)
		(layer "B.Cu")
		(net "GND")
	)
	(segment
		(start 278.505158 -189.79515)
		(end 279.119584 -190.409576)
		(width 0.3556)
		(layer "B.Cu")
		(net "GND")
	)
	(segment
		(start 449.841366 -74.971656)
		(end 449.841366 -75.530456)
		(width 0.3556)
		(layer "B.Cu")
		(net "GND")
	)
	(segment
		(start 73.139808 -10.155936)
		(end 72.82688 -10.468864)
		(width 0.3556)
		(layer "B.Cu")
		(net "GND")
	)
	(segment
		(start 305.189382 -149.533356)
		(end 304.552858 -149.533356)
		(width 0.3556)
		(layer "B.Cu")
		(net "GND")
	)
	(segment
		(start 331.01788 -27.301698)
		(end 331.01788 -25.974548)
		(width 0.3556)
		(layer "B.Cu")
		(net "GND")
	)
	(segment
		(start 54.880002 -319.397888)
		(end 54.880002 -319.009776)
		(width 0.381)
		(layer "B.Cu")
		(net "GND")
	)
	(segment
		(start 148.609558 -188.21019)
		(end 147.96262 -188.857128)
		(width 0.3556)
		(layer "B.Cu")
		(net "GND")
	)
	(segment
		(start 265.006328 -319.147698)
		(end 265.006328 -318.697102)
		(width 0.381)
		(layer "B.Cu")
		(net "GND")
	)
	(segment
		(start 206.71917 -89.918032)
		(end 208.517744 -90.666824)
		(width 0.254)
		(layer "B.Cu")
		(net "GND")
	)
	(segment
		(start 171.755562 -112.97539)
		(end 171.355512 -112.57534)
		(width 0.3556)
		(layer "B.Cu")
		(net "GND")
	)
	(segment
		(start 181.857396 -319.268856)
		(end 181.882796 -319.294256)
		(width 0.381)
		(layer "B.Cu")
		(net "GND")
	)
	(segment
		(start 39.36111 -318.873632)
		(end 39.36111 -319.268856)
		(width 0.3556)
		(layer "B.Cu")
		(net "GND")
	)
	(segment
		(start 324.98919 -26.861008)
		(end 324.98919 -28.0543)
		(width 0.3556)
		(layer "B.Cu")
		(net "GND")
	)
	(segment
		(start 314.094622 -53.228748)
		(end 314.685172 -53.228748)
		(width 0.3556)
		(layer "B.Cu")
		(net "GND")
	)
	(segment
		(start 349.260668 -355.538532)
		(end 348.879414 -355.919786)
		(width 0.381)
		(layer "B.Cu")
		(net "GND")
	)
	(segment
		(start 369.89893 -42.128948)
		(end 370.51488 -42.128948)
		(width 0.3556)
		(layer "B.Cu")
		(net "GND")
	)
	(segment
		(start 320.645282 -25.785318)
		(end 320.7512 -25.6794)
		(width 0.3556)
		(layer "B.Cu")
		(net "GND")
	)
	(segment
		(start 127.7874 -19.914108)
		(end 127.7874 -20.603718)
		(width 0.3556)
		(layer "B.Cu")
		(net "GND")
	)
	(segment
		(start 238.237522 -128.518158)
		(end 238.237522 -127.49022)
		(width 0.3556)
		(layer "B.Cu")
		(net "GND")
	)
	(segment
		(start 306.347622 -30.571948)
		(end 306.500022 -30.724348)
		(width 0.3556)
		(layer "B.Cu")
		(net "GND")
	)
	(segment
		(start 138.907012 -28.22956)
		(end 139.8778 -28.22956)
		(width 0.254)
		(layer "B.Cu")
		(net "GND")
	)
	(segment
		(start 159.84728 -118.354348)
		(end 160.43783 -117.763798)
		(width 0.3556)
		(layer "B.Cu")
		(net "GND")
	)
	(segment
		(start 118.798594 -271.011396)
		(end 119.521986 -270.704056)
		(width 0.0889)
		(layer "B.Cu")
		(net "GND")
	)
	(segment
		(start 137.311638 -271.500854)
		(end 137.312146 -271.500854)
		(width 0.0889)
		(layer "B.Cu")
		(net "GND")
	)
	(segment
		(start 333.386938 -44.34459)
		(end 333.386938 -44.962064)
		(width 0.381)
		(layer "B.Cu")
		(net "GND")
	)
	(segment
		(start 287.384236 -319.351914)
		(end 287.249362 -319.486788)
		(width 0.3048)
		(layer "B.Cu")
		(net "GND")
	)
	(segment
		(start 317.915544 -36.139628)
		(end 318.215264 -36.439348)
		(width 0.3556)
		(layer "B.Cu")
		(net "GND")
	)
	(segment
		(start 115.722908 -358.732836)
		(end 115.556284 -358.566212)
		(width 0.3556)
		(layer "B.Cu")
		(net "GND")
	)
	(segment
		(start 280.011632 -319.520824)
		(end 280.852118 -319.520824)
		(width 0.3556)
		(layer "B.Cu")
		(net "GND")
	)
	(segment
		(start 458.02423 -319.132204)
		(end 457.227178 -319.132204)
		(width 0.3556)
		(layer "B.Cu")
		(net "GND")
	)
	(segment
		(start 143.506952 -30.14218)
		(end 144.737328 -30.14218)
		(width 0.254)
		(layer "B.Cu")
		(net "GND")
	)
	(segment
		(start 330.69403 -24.585422)
		(end 330.69403 -25.212548)
		(width 0.3556)
		(layer "B.Cu")
		(net "GND")
	)
	(segment
		(start 212.724746 -195.616576)
		(end 212.754972 -195.58635)
		(width 0.3556)
		(layer "B.Cu")
		(net "GND")
	)
	(segment
		(start 367.462054 -270.704056)
		(end 367.491264 -270.687038)
		(width 0.0889)
		(layer "B.Cu")
		(net "GND")
	)
	(segment
		(start 250.194064 -87.543386)
		(end 250.744736 -86.992714)
		(width 0.3556)
		(layer "B.Cu")
		(net "GND")
	)
	(segment
		(start 370.229638 -187.71489)
		(end 369.744498 -187.71489)
		(width 0.3556)
		(layer "B.Cu")
		(net "GND")
	)
	(segment
		(start 371.421914 -190.271654)
		(end 369.819682 -190.271654)
		(width 0.3556)
		(layer "B.Cu")
		(net "GND")
	)
	(segment
		(start 31.854648 -319.303908)
		(end 32.157162 -319.001394)
		(width 0.381)
		(layer "B.Cu")
		(net "GND")
	)
	(segment
		(start 190.096902 -319.301876)
		(end 190.599822 -319.301876)
		(width 0.3556)
		(layer "B.Cu")
		(net "GND")
	)
	(segment
		(start 16.67891 -319.268856)
		(end 16.812006 -319.401952)
		(width 0.381)
		(layer "B.Cu")
		(net "GND")
	)
	(segment
		(start 98.49104 -424.457368)
		(end 97.46996 -423.436288)
		(width 0.3556)
		(layer "B.Cu")
		(net "GND")
	)
	(segment
		(start 370.695474 -354.53828)
		(end 371.665246 -354.53828)
		(width 0.3556)
		(layer "B.Cu")
		(net "GND")
	)
	(segment
		(start 264.037064 -319.263776)
		(end 264.17524 -319.401952)
		(width 0.381)
		(layer "B.Cu")
		(net "GND")
	)
	(segment
		(start 371.24005 -270.693134)
		(end 371.250464 -270.687038)
		(width 0.0889)
		(layer "B.Cu")
		(net "GND")
	)
	(segment
		(start 256.49174 -319.48374)
		(end 257.030474 -319.48374)
		(width 0.3556)
		(layer "B.Cu")
		(net "GND")
	)
	(segment
		(start 369.819682 -190.271654)
		(end 369.388898 -189.84087)
		(width 0.3556)
		(layer "B.Cu")
		(net "GND")
	)
	(segment
		(start 147.96262 -189.641988)
		(end 148.28393 -189.963298)
		(width 0.3556)
		(layer "B.Cu")
		(net "GND")
	)
	(segment
		(start 87.489284 -187.816236)
		(end 87.489284 -188.516514)
		(width 0.3556)
		(layer "B.Cu")
		(net "GND")
	)
	(segment
		(start 62.73546 -15.403068)
		(end 62.702186 -15.369794)
		(width 0.3556)
		(layer "B.Cu")
		(net "GND")
	)
	(segment
		(start 136.452864 -270.695674)
		(end 136.467596 -270.687038)
		(width 0.0889)
		(layer "B.Cu")
		(net "GND")
	)
	(segment
		(start 436.18912 -44.44238)
		(end 436.17896 -44.45254)
		(width 0.3556)
		(layer "B.Cu")
		(net "GND")
	)
	(segment
		(start 159.91586 -42.205148)
		(end 159.766508 -42.205148)
		(width 0.3556)
		(layer "B.Cu")
		(net "GND")
	)
	(segment
		(start 19.39671 -177.607976)
		(end 19.588734 -177.415952)
		(width 0.3556)
		(layer "B.Cu")
		(net "GND")
	)
	(segment
		(start 160.43783 -122.646948)
		(end 159.82188 -122.646948)
		(width 0.3556)
		(layer "B.Cu")
		(net "GND")
	)
	(segment
		(start 309.66283 -319.85331)
		(end 309.906162 -319.85331)
		(width 0.3556)
		(layer "B.Cu")
		(net "GND")
	)
	(segment
		(start 210.368388 -91.42984)
		(end 212.209634 -92.202762)
		(width 0.254)
		(layer "B.Cu")
		(net "GND")
	)
	(segment
		(start 235.03128 -51.663346)
		(end 235.485178 -51.209448)
		(width 0.3556)
		(layer "B.Cu")
		(net "GND")
	)
	(segment
		(start 9.182354 -319.268856)
		(end 9.258046 -319.344548)
		(width 0.3556)
		(layer "B.Cu")
		(net "GND")
	)
	(segment
		(start 344.480642 -33.418526)
		(end 344.864944 -33.418526)
		(width 0.3556)
		(layer "B.Cu")
		(net "GND")
	)
	(segment
		(start 133.5786 -26.47315)
		(end 134.2136 -26.47315)
		(width 0.3556)
		(layer "B.Cu")
		(net "GND")
	)
	(segment
		(start 204.0001 -103.762048)
		(end 205.446122 -105.20807)
		(width 0.3556)
		(layer "B.Cu")
		(net "GND")
	)
	(segment
		(start 379.693932 -270.695674)
		(end 379.708664 -270.687038)
		(width 0.0889)
		(layer "B.Cu")
		(net "GND")
	)
	(segment
		(start 190.65113 -18.938748)
		(end 191.280796 -18.938748)
		(width 0.3556)
		(layer "B.Cu")
		(net "GND")
	)
	(segment
		(start 432.562 -24.494998)
		(end 431.546 -24.494998)
		(width 0.3556)
		(layer "B.Cu")
		(net "GND")
	)
	(segment
		(start 45.75683 -335.477612)
		(end 46.697138 -335.477612)
		(width 0.508)
		(layer "B.Cu")
		(net "GND")
	)
	(segment
		(start 421.859964 -138.874246)
		(end 422.218104 -138.516106)
		(width 0.381)
		(layer "B.Cu")
		(net "GND")
	)
	(segment
		(start 302.505364 -319.712594)
		(end 302.749204 -319.468754)
		(width 0.3556)
		(layer "B.Cu")
		(net "GND")
	)
	(segment
		(start 120.72239 -354.799138)
		(end 120.72239 -354.432108)
		(width 0.3556)
		(layer "B.Cu")
		(net "GND")
	)
	(segment
		(start 203.181458 -194.03441)
		(end 203.107798 -193.96075)
		(width 0.3556)
		(layer "B.Cu")
		(net "GND")
	)
	(segment
		(start 420.285418 -193.753486)
		(end 421.304466 -193.753486)
		(width 0.3556)
		(layer "B.Cu")
		(net "GND")
	)
	(segment
		(start 310.243474 -32.3342)
		(end 310.152542 -32.243268)
		(width 0.381)
		(layer "B.Cu")
		(net "GND")
	)
	(segment
		(start 179.9082 -107.1626)
		(end 179.542948 -107.1626)
		(width 0.3556)
		(layer "B.Cu")
		(net "GND")
	)
	(segment
		(start 220.452188 -95.6183)
		(end 222.484188 -96.467422)
		(width 0.254)
		(layer "B.Cu")
		(net "GND")
	)
	(segment
		(start 431.546 -24.494998)
		(end 430.7713 -24.494998)
		(width 0.3556)
		(layer "B.Cu")
		(net "GND")
	)
	(segment
		(start 386.944616 -271.450054)
		(end 387.273546 -271.450054)
		(width 0.0889)
		(layer "B.Cu")
		(net "GND")
	)
	(segment
		(start 96.241108 -188.27496)
		(end 96.241108 -190.305182)
		(width 0.3556)
		(layer "B.Cu")
		(net "GND")
	)
	(segment
		(start 193.991738 -194.14109)
		(end 193.958718 -194.10807)
		(width 0.3556)
		(layer "B.Cu")
		(net "GND")
	)
	(segment
		(start 234.259628 -422.61155)
		(end 234.26928 -422.601898)
		(width 0.3556)
		(layer "B.Cu")
		(net "GND")
	)
	(segment
		(start 437.341264 -319.263776)
		(end 437.989472 -319.263776)
		(width 0.3556)
		(layer "B.Cu")
		(net "GND")
	)
	(segment
		(start 339.740748 -31.529528)
		(end 339.58022 -31.529528)
		(width 0.3556)
		(layer "B.Cu")
		(net "GND")
	)
	(segment
		(start 445.639952 -319.345056)
		(end 445.779906 -319.205102)
		(width 0.3556)
		(layer "B.Cu")
		(net "GND")
	)
	(segment
		(start 370.300504 -270.693134)
		(end 370.310918 -270.687038)
		(width 0.0889)
		(layer "B.Cu")
		(net "GND")
	)
	(segment
		(start 431.000154 -136.526778)
		(end 431.619914 -136.526778)
		(width 0.381)
		(layer "B.Cu")
		(net "GND")
	)
	(segment
		(start 329.134978 -28.234386)
		(end 329.134978 -28.452572)
		(width 0.3556)
		(layer "B.Cu")
		(net "GND")
	)
	(segment
		(start 244.819424 -100.127308)
		(end 244.82552 -100.121212)
		(width 0.381)
		(layer "B.Cu")
		(net "GND")
	)
	(segment
		(start 415.464752 -319.446656)
		(end 415.680906 -319.230502)
		(width 0.3556)
		(layer "B.Cu")
		(net "GND")
	)
	(segment
		(start 330.952856 -31.656782)
		(end 331.146912 -31.850838)
		(width 0.381)
		(layer "B.Cu")
		(net "GND")
	)
	(segment
		(start 396.20444 -60.960508)
		(end 396.29207 -61.048138)
		(width 0.3556)
		(layer "B.Cu")
		(net "GND")
	)
	(segment
		(start 337.552284 -32.9438)
		(end 337.552284 -33.32607)
		(width 0.3556)
		(layer "B.Cu")
		(net "GND")
	)
	(segment
		(start 431.52568 -177.434748)
		(end 431.52568 -177.206148)
		(width 0.3556)
		(layer "B.Cu")
		(net "GND")
	)
	(segment
		(start 186.155838 -117.11813)
		(end 186.155838 -116.975382)
		(width 0.3556)
		(layer "B.Cu")
		(net "GND")
	)
	(segment
		(start 370.7892 -186.131708)
		(end 371.652038 -186.131708)
		(width 0.3556)
		(layer "B.Cu")
		(net "GND")
	)
	(segment
		(start 395.62024 -50.015648)
		(end 396.06855 -50.463958)
		(width 0.3556)
		(layer "B.Cu")
		(net "GND")
	)
	(segment
		(start 139.410186 -271.450054)
		(end 139.58316 -271.623028)
		(width 0.088646)
		(layer "B.Cu")
		(net "GND")
	)
	(segment
		(start 317.525654 -65.048892)
		(end 316.596776 -65.048892)
		(width 0.3556)
		(layer "B.Cu")
		(net "GND")
	)
	(segment
		(start 457.0349 -49.476406)
		(end 457.732638 -48.778668)
		(width 0.508)
		(layer "B.Cu")
		(net "GND")
	)
	(segment
		(start 405.486108 -54.754272)
		(end 404.411942 -54.754272)
		(width 0.3556)
		(layer "B.Cu")
		(net "GND")
	)
	(segment
		(start 422.218104 -138.516106)
		(end 422.218104 -138.058144)
		(width 0.381)
		(layer "B.Cu")
		(net "GND")
	)
	(segment
		(start 182.275988 -103.72979)
		(end 182.28183 -103.723948)
		(width 0.3556)
		(layer "B.Cu")
		(net "GND")
	)
	(segment
		(start 120.3706 -367.802668)
		(end 118.96344 -366.395508)
		(width 0.3556)
		(layer "B.Cu")
		(net "GND")
	)
	(segment
		(start 293.497 -344.700352)
		(end 294.437308 -344.700352)
		(width 0.508)
		(layer "B.Cu")
		(net "GND")
	)
	(segment
		(start 135.513064 -270.695674)
		(end 135.527796 -270.687038)
		(width 0.0889)
		(layer "B.Cu")
		(net "GND")
	)
	(segment
		(start 238.236252 -127.48895)
		(end 238.236252 -126.520956)
		(width 0.3556)
		(layer "B.Cu")
		(net "GND")
	)
	(segment
		(start 128.934464 -270.695674)
		(end 128.949196 -270.687038)
		(width 0.0889)
		(layer "B.Cu")
		(net "GND")
	)
	(segment
		(start 46.272196 -319.268856)
		(end 46.486064 -319.268856)
		(width 0.381)
		(layer "B.Cu")
		(net "GND")
	)
	(segment
		(start 370.600478 -186.32043)
		(end 370.7892 -186.131708)
		(width 0.3556)
		(layer "B.Cu")
		(net "GND")
	)
	(segment
		(start 341.921338 -53.148992)
		(end 341.161624 -53.908706)
		(width 0.381)
		(layer "B.Cu")
		(net "GND")
	)
	(segment
		(start 258.784852 -106.819192)
		(end 259.399786 -106.819192)
		(width 0.381)
		(layer "B.Cu")
		(net "GND")
	)
	(segment
		(start 187.355734 -104.575356)
		(end 187.604146 -104.823768)
		(width 0.3556)
		(layer "B.Cu")
		(net "GND")
	)
	(segment
		(start 208.915 -72.80275)
		(end 210.160362 -72.80275)
		(width 0.3556)
		(layer "B.Cu")
		(net "GND")
	)
	(segment
		(start 452.428864 -319.263776)
		(end 453.000872 -319.263776)
		(width 0.3556)
		(layer "B.Cu")
		(net "GND")
	)
	(segment
		(start 344.864944 -33.418526)
		(end 345.220798 -33.062672)
		(width 0.3556)
		(layer "B.Cu")
		(net "GND")
	)
	(segment
		(start 77.90688 -10.867898)
		(end 77.90688 -10.155428)
		(width 0.3556)
		(layer "B.Cu")
		(net "GND")
	)
	(segment
		(start 450.25818 -9.583928)
		(end 450.482716 -9.808464)
		(width 0.3556)
		(layer "B.Cu")
		(net "GND")
	)
	(segment
		(start 407.938986 -318.680592)
		(end 408.01417 -318.755776)
		(width 0.3556)
		(layer "B.Cu")
		(net "GND")
	)
	(segment
		(start 74.04608 -3.851148)
		(end 74.04608 -3.241548)
		(width 0.3556)
		(layer "B.Cu")
		(net "GND")
	)
	(segment
		(start 139.60094 -30.653228)
		(end 139.50569 -30.557978)
		(width 0.3556)
		(layer "B.Cu")
		(net "GND")
	)
	(segment
		(start 170.965622 -334.461612)
		(end 170.965622 -335.477612)
		(width 0.508)
		(layer "B.Cu")
		(net "GND")
	)
	(segment
		(start 6.2738 -195.6562)
		(end 6.834378 -196.216778)
		(width 0.3556)
		(layer "B.Cu")
		(net "GND")
	)
	(segment
		(start 138.251946 -271.500854)
		(end 138.266678 -271.50949)
		(width 0.0889)
		(layer "B.Cu")
		(net "GND")
	)
	(segment
		(start 70.012306 -207.544162)
		(end 70.012306 -219.423488)
		(width 0.3556)
		(layer "B.Cu")
		(net "GND")
	)
	(segment
		(start 197.699884 -319.345056)
		(end 197.686422 -319.331594)
		(width 0.381)
		(layer "B.Cu")
		(net "GND")
	)
	(segment
		(start 268.668246 -194.605656)
		(end 268.668246 -193.903346)
		(width 0.3048)
		(layer "B.Cu")
		(net "GND")
	)
	(segment
		(start 421.292528 -344.017346)
		(end 422.232836 -344.017346)
		(width 0.508)
		(layer "B.Cu")
		(net "GND")
	)
	(segment
		(start 203.7842 -193.984118)
		(end 203.733908 -194.03441)
		(width 0.3556)
		(layer "B.Cu")
		(net "GND")
	)
	(segment
		(start 310.152542 -32.243268)
		(end 309.958232 -32.243268)
		(width 0.381)
		(layer "B.Cu")
		(net "GND")
	)
	(segment
		(start 422.253664 -319.263776)
		(end 422.512744 -319.522856)
		(width 0.3556)
		(layer "B.Cu")
		(net "GND")
	)
	(segment
		(start 171.715684 -319.522856)
		(end 171.207684 -319.014856)
		(width 0.381)
		(layer "B.Cu")
		(net "GND")
	)
	(segment
		(start 279.119584 -193.269616)
		(end 280.110184 -193.269616)
		(width 0.3556)
		(layer "B.Cu")
		(net "GND")
	)
	(segment
		(start 228.88194 -125.938788)
		(end 228.71684 -125.938788)
		(width 0.3556)
		(layer "B.Cu")
		(net "GND")
	)
	(segment
		(start 437.989472 -319.263776)
		(end 438.045352 -319.319656)
		(width 0.3556)
		(layer "B.Cu")
		(net "GND")
	)
	(segment
		(start 87.489284 -188.516514)
		(end 87.48776 -188.518038)
		(width 0.3556)
		(layer "B.Cu")
		(net "GND")
	)
	(segment
		(start 287.695386 -319.925192)
		(end 287.672018 -319.925192)
		(width 0.3048)
		(layer "B.Cu")
		(net "GND")
	)
	(segment
		(start 278.505158 -189.07379)
		(end 278.505158 -189.79515)
		(width 0.3556)
		(layer "B.Cu")
		(net "GND")
	)
	(segment
		(start 334.13192 -49.087278)
		(end 334.19669 -49.022508)
		(width 0.381)
		(layer "B.Cu")
		(net "GND")
	)
	(segment
		(start 121.97588 -381.122428)
		(end 120.3706 -379.517148)
		(width 0.3556)
		(layer "B.Cu")
		(net "GND")
	)
	(segment
		(start 136.48944 -30.612588)
		(end 136.2075 -30.330648)
		(width 0.3556)
		(layer "B.Cu")
		(net "GND")
	)
	(segment
		(start 14.727174 -191.724788)
		(end 13.931138 -191.724788)
		(width 0.3556)
		(layer "B.Cu")
		(net "GND")
	)
	(segment
		(start 148.699474 -189.618874)
		(end 148.699474 -189.963298)
		(width 0.3556)
		(layer "B.Cu")
		(net "GND")
	)
	(segment
		(start 50.698908 -192.85966)
		(end 50.698908 -192.24117)
		(width 0.381)
		(layer "B.Cu")
		(net "GND")
	)
	(segment
		(start 387.273546 -271.450054)
		(end 387.45668 -271.633188)
		(width 0.0889)
		(layer "B.Cu")
		(net "GND")
	)
	(segment
		(start 259.06349 -51.646582)
		(end 259.06349 -51.535076)
		(width 0.3556)
		(layer "B.Cu")
		(net "GND")
	)
	(segment
		(start 193.958718 -194.10807)
		(end 193.958718 -193.63436)
		(width 0.3556)
		(layer "B.Cu")
		(net "GND")
	)
	(segment
		(start 453.000872 -319.263776)
		(end 453.183752 -319.446656)
		(width 0.3556)
		(layer "B.Cu")
		(net "GND")
	)
	(segment
		(start 367.852198 -190.39713)
		(end 368.832638 -190.39713)
		(width 0.3556)
		(layer "B.Cu")
		(net "GND")
	)
	(segment
		(start 183.353964 -334.467962)
		(end 183.353964 -335.483962)
		(width 0.508)
		(layer "B.Cu")
		(net "GND")
	)
	(segment
		(start 304.552858 -149.533356)
		(end 303.872392 -149.533356)
		(width 0.3556)
		(layer "B.Cu")
		(net "GND")
	)
	(segment
		(start 262.60044 -101.803708)
		(end 262.392414 -101.595682)
		(width 0.3556)
		(layer "B.Cu")
		(net "GND")
	)
	(segment
		(start 438.286906 -319.078102)
		(end 438.286906 -318.603376)
		(width 0.3556)
		(layer "B.Cu")
		(net "GND")
	)
	(segment
		(start 28.574238 -131.735068)
		(end 28.574238 -131.277106)
		(width 0.381)
		(layer "B.Cu")
		(net "GND")
	)
	(segment
		(start 179.432458 -31.181548)
		(end 178.069748 -32.544258)
		(width 0.3556)
		(layer "B.Cu")
		(net "GND")
	)
	(segment
		(start 119.737632 -362.052616)
		(end 120.910604 -362.052616)
		(width 0.3556)
		(layer "B.Cu")
		(net "GND")
	)
	(segment
		(start 455.26833 -380.87046)
		(end 455.26833 -382.435608)
		(width 0.3556)
		(layer "B.Cu")
		(net "GND")
	)
	(segment
		(start 415.281872 -319.263776)
		(end 415.464752 -319.446656)
		(width 0.3556)
		(layer "B.Cu")
		(net "GND")
	)
	(segment
		(start 408.9781 -318.93637)
		(end 408.797506 -318.755776)
		(width 0.3556)
		(layer "B.Cu")
		(net "GND")
	)
	(segment
		(start 178.069748 -32.544258)
		(end 178.04384 -32.544258)
		(width 0.3556)
		(layer "B.Cu")
		(net "GND")
	)
	(segment
		(start 430.81448 -128.761998)
		(end 431.24374 -129.191258)
		(width 0.3556)
		(layer "B.Cu")
		(net "GND")
	)
	(segment
		(start 63.718186 -15.372334)
		(end 63.687452 -15.403068)
		(width 0.3556)
		(layer "B.Cu")
		(net "GND")
	)
	(segment
		(start 160.952942 -319.567306)
		(end 160.952942 -319.106042)
		(width 0.381)
		(layer "B.Cu")
		(net "GND")
	)
	(segment
		(start 203.733908 -192.95491)
		(end 203.7842 -193.005202)
		(width 0.3556)
		(layer "B.Cu")
		(net "GND")
	)
	(segment
		(start 287.2994 -344.700352)
		(end 288.239708 -344.700352)
		(width 0.508)
		(layer "B.Cu")
		(net "GND")
	)
	(segment
		(start 155.83408 -119.421148)
		(end 156.41828 -119.421148)
		(width 0.3556)
		(layer "B.Cu")
		(net "GND")
	)
	(segment
		(start 310.6674 -32.3342)
		(end 310.243474 -32.3342)
		(width 0.381)
		(layer "B.Cu")
		(net "GND")
	)
	(segment
		(start 450.482716 -9.808464)
		(end 450.482716 -10.194036)
		(width 0.3556)
		(layer "B.Cu")
		(net "GND")
	)
	(segment
		(start 128.86944 -36.351718)
		(end 128.86944 -35.684968)
		(width 0.3556)
		(layer "B.Cu")
		(net "GND")
	)
	(segment
		(start 368.416332 -270.695674)
		(end 368.431064 -270.687038)
		(width 0.0889)
		(layer "B.Cu")
		(net "GND")
	)
	(segment
		(start 197.59041 -120.614948)
		(end 198.20636 -120.614948)
		(width 0.3556)
		(layer "B.Cu")
		(net "GND")
	)
	(segment
		(start 177.156364 -334.467962)
		(end 177.156364 -335.483962)
		(width 0.508)
		(layer "B.Cu")
		(net "GND")
	)
	(segment
		(start 431.98034 -50.66919)
		(end 431.98034 -49.78654)
		(width 0.3556)
		(layer "B.Cu")
		(net "GND")
	)
	(segment
		(start 259.064506 -77.272896)
		(end 259.064506 -76.991972)
		(width 0.381)
		(layer "B.Cu")
		(net "GND")
	)
	(segment
		(start 294.91051 -319.753234)
		(end 295.086278 -319.577466)
		(width 0.3556)
		(layer "B.Cu")
		(net "GND")
	)
	(segment
		(start 205.243684 -319.446656)
		(end 205.243684 -318.956944)
		(width 0.381)
		(layer "B.Cu")
		(net "GND")
	)
	(segment
		(start 431.975768 -176.75606)
		(end 432.325018 -176.75606)
		(width 0.3556)
		(layer "B.Cu")
		(net "GND")
	)
	(segment
		(start 319.97523 -36.838128)
		(end 320.297048 -37.159946)
		(width 0.3556)
		(layer "B.Cu")
		(net "GND")
	)
	(segment
		(start 115.556284 -358.566212)
		(end 115.093496 -358.566212)
		(width 0.3556)
		(layer "B.Cu")
		(net "GND")
	)
	(segment
		(start 156.548074 -196.776848)
		(end 155.756102 -196.776848)
		(width 0.381)
		(layer "B.Cu")
		(net "GND")
	)
	(segment
		(start 252.320298 -109.176058)
		(end 252.320298 -108.977684)
		(width 0.381)
		(layer "B.Cu")
		(net "GND")
	)
	(segment
		(start 167.082216 -246.616728)
		(end 166.701216 -246.997728)
		(width 0.381)
		(layer "B.Cu")
		(net "GND")
	)
	(segment
		(start 328.765916 -27.865324)
		(end 329.134978 -28.234386)
		(width 0.3556)
		(layer "B.Cu")
		(net "GND")
	)
	(segment
		(start 369.56238 -382.288288)
		(end 367.89868 -380.624588)
		(width 0.3556)
		(layer "B.Cu")
		(net "GND")
	)
	(segment
		(start 259.06349 -51.535076)
		(end 259.77469 -50.823876)
		(width 0.3556)
		(layer "B.Cu")
		(net "GND")
	)
	(segment
		(start 197.420484 -319.268856)
		(end 197.496684 -319.345056)
		(width 0.381)
		(layer "B.Cu")
		(net "GND")
	)
	(segment
		(start 166.701216 -246.997728)
		(end 166.701216 -247.250712)
		(width 0.381)
		(layer "B.Cu")
		(net "GND")
	)
	(segment
		(start 326.692006 -74.617072)
		(end 326.438006 -74.871072)
		(width 0.3556)
		(layer "B.Cu")
		(net "GND")
	)
	(segment
		(start 461.918812 -318.39154)
		(end 461.419448 -318.39154)
		(width 0.3556)
		(layer "B.Cu")
		(net "GND")
	)
	(segment
		(start 338.553044 -32.037528)
		(end 339.061044 -31.529528)
		(width 0.3556)
		(layer "B.Cu")
		(net "GND")
	)
	(segment
		(start 197.28307 -192.617598)
		(end 197.795896 -192.617598)
		(width 0.3556)
		(layer "B.Cu")
		(net "GND")
	)
	(segment
		(start 396.06855 -50.463958)
		(end 396.72006 -50.463958)
		(width 0.3556)
		(layer "B.Cu")
		(net "GND")
	)
	(segment
		(start 173.755558 -105.23855)
		(end 174.018702 -104.975406)
		(width 0.3556)
		(layer "B.Cu")
		(net "GND")
	)
	(segment
		(start 208.517744 -90.666824)
		(end 210.368388 -91.42984)
		(width 0.254)
		(layer "B.Cu")
		(net "GND")
	)
	(segment
		(start 264.17524 -319.401952)
		(end 264.752074 -319.401952)
		(width 0.381)
		(layer "B.Cu")
		(net "GND")
	)
	(segment
		(start 450.710808 -76.297536)
		(end 450.732398 -76.319126)
		(width 0.3556)
		(layer "B.Cu")
		(net "GND")
	)
	(segment
		(start 373.115332 -270.695674)
		(end 373.130064 -270.687038)
		(width 0.0889)
		(layer "B.Cu")
		(net "GND")
	)
	(segment
		(start 381.750824 -364.65002)
		(end 381.750824 -365.64062)
		(width 0.508)
		(layer "B.Cu")
		(net "GND")
	)
	(segment
		(start 121.382028 -354.565204)
		(end 121.757694 -354.189538)
		(width 0.381)
		(layer "B.Cu")
		(net "GND")
	)
	(segment
		(start 448.836796 -9.224264)
		(end 447.818764 -9.224264)
		(width 0.3556)
		(layer "B.Cu")
		(net "GND")
	)
	(segment
		(start 196.930518 -192.97015)
		(end 197.28307 -192.617598)
		(width 0.3556)
		(layer "B.Cu")
		(net "GND")
	)
	(segment
		(start 213.18093 -318.90081)
		(end 213.18093 -318.784478)
		(width 0.381)
		(layer "B.Cu")
		(net "GND")
	)
	(segment
		(start 263.37641 -73.906126)
		(end 263.37641 -74.480928)
		(width 0.3556)
		(layer "B.Cu")
		(net "GND")
	)
	(segment
		(start 287.249362 -319.486788)
		(end 286.891476 -319.486788)
		(width 0.3048)
		(layer "B.Cu")
		(net "GND")
	)
	(segment
		(start 359.16108 -360.847386)
		(end 358.51719 -360.847386)
		(width 0.381)
		(layer "B.Cu")
		(net "GND")
	)
	(segment
		(start 182.637684 -319.294256)
		(end 182.611776 -319.268348)
		(width 0.381)
		(layer "B.Cu")
		(net "GND")
	)
	(segment
		(start 431.428398 -194.56781)
		(end 432.030886 -193.965322)
		(width 0.3556)
		(layer "B.Cu")
		(net "GND")
	)
	(segment
		(start 218.372436 -94.750128)
		(end 220.452188 -95.6183)
		(width 0.254)
		(layer "B.Cu")
		(net "GND")
	)
	(segment
		(start 52.894738 -334.537304)
		(end 52.894738 -335.477612)
		(width 0.508)
		(layer "B.Cu")
		(net "GND")
	)
	(segment
		(start 173.755558 -121.375424)
		(end 173.755558 -121.528586)
		(width 0.3556)
		(layer "B.Cu")
		(net "GND")
	)
	(segment
		(start 164.24783 -120.106948)
		(end 163.63823 -120.106948)
		(width 0.3556)
		(layer "B.Cu")
		(net "GND")
	)
	(segment
		(start 343.157302 -52.602384)
		(end 342.453214 -52.602384)
		(width 0.3556)
		(layer "B.Cu")
		(net "GND")
	)
	(segment
		(start 170.42257 -117.375432)
		(end 170.155616 -117.108478)
		(width 0.3556)
		(layer "B.Cu")
		(net "GND")
	)
	(segment
		(start 232.580434 -129.962148)
		(end 232.692194 -130.073908)
		(width 0.381)
		(layer "B.Cu")
		(net "GND")
	)
	(segment
		(start 47.289466 -319.43421)
		(end 47.289466 -319.009522)
		(width 0.381)
		(layer "B.Cu")
		(net "GND")
	)
	(segment
		(start 121.382028 -355.194108)
		(end 121.382028 -354.565204)
		(width 0.381)
		(layer "B.Cu")
		(net "GND")
	)
	(segment
		(start 148.878798 -188.21019)
		(end 148.609558 -188.21019)
		(width 0.3556)
		(layer "B.Cu")
		(net "GND")
	)
	(segment
		(start 402.65858 -272.987008)
		(end 403.43582 -273.764248)
		(width 0.3556)
		(layer "B.Cu")
		(net "GND")
	)
	(segment
		(start 415.101786 -343.070688)
		(end 415.101786 -344.010996)
		(width 0.508)
		(layer "B.Cu")
		(net "GND")
	)
	(segment
		(start 134.573264 -270.695674)
		(end 134.587996 -270.687038)
		(width 0.0889)
		(layer "B.Cu")
		(net "GND")
	)
	(segment
		(start 399.49628 -271.633188)
		(end 400.8501 -272.987008)
		(width 0.3556)
		(layer "B.Cu")
		(net "GND")
	)
	(segment
		(start 170.555666 -117.375432)
		(end 170.42257 -117.375432)
		(width 0.3556)
		(layer "B.Cu")
		(net "GND")
	)
	(segment
		(start 208.900268 -193.641726)
		(end 209.370168 -193.171826)
		(width 0.3556)
		(layer "B.Cu")
		(net "GND")
	)
	(segment
		(start 139.293854 -271.450054)
		(end 139.410186 -271.450054)
		(width 0.088646)
		(layer "B.Cu")
		(net "GND")
	)
	(segment
		(start 311.44083 -54.320948)
		(end 311.44083 -53.304948)
		(width 0.3556)
		(layer "B.Cu")
		(net "GND")
	)
	(segment
		(start 204.666596 -319.446656)
		(end 205.243684 -319.446656)
		(width 0.381)
		(layer "B.Cu")
		(net "GND")
	)
	(segment
		(start 369.89893 -40.096948)
		(end 370.51488 -40.096948)
		(width 0.381)
		(layer "B.Cu")
		(net "GND")
	)
	(segment
		(start 210.64728 -75.377548)
		(end 210.711034 -75.313794)
		(width 0.3556)
		(layer "B.Cu")
		(net "GND")
	)
	(segment
		(start 365.68761 -182.480458)
		(end 365.042958 -183.12511)
		(width 0.3556)
		(layer "B.Cu")
		(net "GND")
	)
	(segment
		(start 33.773618 -193.17335)
		(end 33.924494 -193.324226)
		(width 0.3556)
		(layer "B.Cu")
		(net "GND")
	)
	(segment
		(start 46.486064 -319.268856)
		(end 46.970442 -319.753234)
		(width 0.381)
		(layer "B.Cu")
		(net "GND")
	)
	(segment
		(start 314.685172 -53.228748)
		(end 314.710572 -53.203348)
		(width 0.3556)
		(layer "B.Cu")
		(net "GND")
	)
	(segment
		(start 39.566088 -335.471262)
		(end 40.506396 -335.471262)
		(width 0.508)
		(layer "B.Cu")
		(net "GND")
	)
	(segment
		(start 170.555666 -109.375448)
		(end 170.411394 -109.375448)
		(width 0.3556)
		(layer "B.Cu")
		(net "GND")
	)
	(segment
		(start 14.407388 -110.604554)
		(end 13.6652 -110.604554)
		(width 0.3556)
		(layer "B.Cu")
		(net "GND")
	)
	(segment
		(start 17.196308 -319.01765)
		(end 17.196308 -318.666622)
		(width 0.381)
		(layer "B.Cu")
		(net "GND")
	)
	(segment
		(start 162.8521 -379.628908)
		(end 161.35858 -381.122428)
		(width 0.3556)
		(layer "B.Cu")
		(net "GND")
	)
	(segment
		(start 403.43582 -273.764248)
		(end 403.43582 -337.558888)
		(width 0.3556)
		(layer "B.Cu")
		(net "GND")
	)
	(segment
		(start 301.756064 -319.263776)
		(end 302.056546 -319.263776)
		(width 0.3556)
		(layer "B.Cu")
		(net "GND")
	)
	(segment
		(start 35.586416 -395.643608)
		(end 35.586416 -396.274544)
		(width 0.4572)
		(layer "B.Cu")
		(net "GND")
	)
	(segment
		(start 435.48681 -43.74007)
		(end 436.18912 -44.44238)
		(width 0.3556)
		(layer "B.Cu")
		(net "GND")
	)
	(segment
		(start 317.358014 -31.523178)
		(end 317.502794 -31.523178)
		(width 0.3556)
		(layer "B.Cu")
		(net "GND")
	)
	(segment
		(start 283.430726 -194.091306)
		(end 283.430726 -194.280536)
		(width 0.3556)
		(layer "B.Cu")
		(net "GND")
	)
	(segment
		(start 365.68761 -182.151528)
		(end 365.68761 -182.480458)
		(width 0.3556)
		(layer "B.Cu")
		(net "GND")
	)
	(segment
		(start 334.099408 -49.650396)
		(end 334.094074 -49.645062)
		(width 0.381)
		(layer "B.Cu")
		(net "GND")
	)
	(segment
		(start 170.411394 -109.375448)
		(end 170.155616 -109.631226)
		(width 0.3556)
		(layer "B.Cu")
		(net "GND")
	)
	(segment
		(start 38.728396 -319.268856)
		(end 39.36111 -319.268856)
		(width 0.381)
		(layer "B.Cu")
		(net "GND")
	)
	(segment
		(start 456.337162 -50.174144)
		(end 457.0349 -49.476406)
		(width 0.508)
		(layer "B.Cu")
		(net "GND")
	)
	(segment
		(start 363.656118 -357.91775)
		(end 363.029754 -358.544114)
		(width 0.381)
		(layer "B.Cu")
		(net "GND")
	)
	(segment
		(start 238.911384 -126.656592)
		(end 238.767874 -126.513082)
		(width 0.3556)
		(layer "B.Cu")
		(net "GND")
	)
	(segment
		(start 432.030886 -193.965322)
		(end 432.523392 -193.965322)
		(width 0.3556)
		(layer "B.Cu")
		(net "GND")
	)
	(segment
		(start 213.27745 -318.107568)
		(end 213.18093 -318.107568)
		(width 0.381)
		(layer "B.Cu")
		(net "GND")
	)
	(segment
		(start 89.541858 -181.73319)
		(end 89.99347 -181.281578)
		(width 0.3556)
		(layer "B.Cu")
		(net "GND")
	)
	(segment
		(start 31.184596 -319.268856)
		(end 31.819596 -319.268856)
		(width 0.381)
		(layer "B.Cu")
		(net "GND")
	)
	(segment
		(start 327.66127 -74.617072)
		(end 326.692006 -74.617072)
		(width 0.3556)
		(layer "B.Cu")
		(net "GND")
	)
	(segment
		(start 349.678244 -355.538532)
		(end 349.260668 -355.538532)
		(width 0.381)
		(layer "B.Cu")
		(net "GND")
	)
	(segment
		(start 6.834378 -196.216778)
		(end 10.373106 -196.216778)
		(width 0.3556)
		(layer "B.Cu")
		(net "GND")
	)
	(segment
		(start 133.725412 -365.747808)
		(end 134.42315 -365.05007)
		(width 0.508)
		(layer "B.Cu")
		(net "GND")
	)
	(segment
		(start 369.89893 -38.953948)
		(end 370.51488 -38.953948)
		(width 0.3556)
		(layer "B.Cu")
		(net "GND")
	)
	(segment
		(start 430.768506 -319.103502)
		(end 430.768506 -318.577976)
		(width 0.3556)
		(layer "B.Cu")
		(net "GND")
	)
	(segment
		(start 420.35222 -344.017346)
		(end 421.292528 -344.017346)
		(width 0.508)
		(layer "B.Cu")
		(net "GND")
	)
	(segment
		(start 328.765916 -26.901648)
		(end 328.765916 -27.865324)
		(width 0.3556)
		(layer "B.Cu")
		(net "GND")
	)
	(segment
		(start 257.185922 -319.328292)
		(end 257.51282 -319.001394)
		(width 0.3556)
		(layer "B.Cu")
		(net "GND")
	)
	(segment
		(start 46.697138 -334.537304)
		(end 46.697138 -335.477612)
		(width 0.508)
		(layer "B.Cu")
		(net "GND")
	)
	(segment
		(start 16.637762 -112.693958)
		(end 17.36471 -112.693958)
		(width 0.3556)
		(layer "B.Cu")
		(net "GND")
	)
	(segment
		(start 436.17896 -45.49394)
		(end 435.518306 -46.154594)
		(width 0.3556)
		(layer "B.Cu")
		(net "GND")
	)
	(segment
		(start 372.299738 -355.95687)
		(end 372.299738 -354.89388)
		(width 0.3556)
		(layer "B.Cu")
		(net "GND")
	)
	(segment
		(start 246.984266 -128.743964)
		(end 246.984266 -129.362962)
		(width 0.3556)
		(layer "B.Cu")
		(net "GND")
	)
	(segment
		(start 75.071478 -200.99655)
		(end 71.167498 -204.90053)
		(width 0.3556)
		(layer "B.Cu")
		(net "GND")
	)
	(segment
		(start 384.306318 -271.497298)
		(end 384.312414 -271.500854)
		(width 0.0889)
		(layer "B.Cu")
		(net "GND")
	)
	(segment
		(start 161.35858 -381.122428)
		(end 121.97588 -381.122428)
		(width 0.3556)
		(layer "B.Cu")
		(net "GND")
	)
	(segment
		(start 326.16648 -62.77229)
		(end 326.16648 -62.158118)
		(width 0.381)
		(layer "B.Cu")
		(net "GND")
	)
	(segment
		(start 156.62783 -119.211598)
		(end 156.62783 -118.836948)
		(width 0.3556)
		(layer "B.Cu")
		(net "GND")
	)
	(segment
		(start 423.084752 -319.522856)
		(end 423.250106 -319.357502)
		(width 0.3556)
		(layer "B.Cu")
		(net "GND")
	)
	(segment
		(start 179.494942 -31.181548)
		(end 179.432458 -31.181548)
		(width 0.3556)
		(layer "B.Cu")
		(net "GND")
	)
	(segment
		(start 236.27588 -49.120044)
		(end 236.22508 -49.069244)
		(width 0.3556)
		(layer "B.Cu")
		(net "GND")
	)
	(segment
		(start 312.132472 -38.809168)
		(end 312.178192 -38.763448)
		(width 0.3556)
		(layer "B.Cu")
		(net "GND")
	)
	(segment
		(start 16.812006 -319.401952)
		(end 17.196308 -319.01765)
		(width 0.381)
		(layer "B.Cu")
		(net "GND")
	)
	(segment
		(start 349.673164 -356.305612)
		(end 349.764604 -356.397052)
		(width 0.381)
		(layer "B.Cu")
		(net "GND")
	)
	(segment
		(start 430.547272 -319.263776)
		(end 430.577752 -319.294256)
		(width 0.3556)
		(layer "B.Cu")
		(net "GND")
	)
	(segment
		(start 139.58316 -271.623028)
		(end 151.5491 -271.623028)
		(width 0.3556)
		(layer "B.Cu")
		(net "GND")
	)
	(segment
		(start 435.05628 -43.74007)
		(end 435.48681 -43.74007)
		(width 0.3556)
		(layer "B.Cu")
		(net "GND")
	)
	(segment
		(start 155.551378 -195.44919)
		(end 156.045408 -194.95516)
		(width 0.3556)
		(layer "B.Cu")
		(net "GND")
	)
	(segment
		(start 427.490128 -343.077038)
		(end 427.490128 -344.017346)
		(width 0.508)
		(layer "B.Cu")
		(net "GND")
	)
	(segment
		(start 157.708346 -195.616576)
		(end 156.548074 -196.776848)
		(width 0.381)
		(layer "B.Cu")
		(net "GND")
	)
	(segment
		(start 213.295484 -318.669924)
		(end 213.295484 -318.125602)
		(width 0.381)
		(layer "B.Cu")
		(net "GND")
	)
	(segment
		(start 330.73848 -25.256998)
		(end 330.69403 -25.212548)
		(width 0.3556)
		(layer "B.Cu")
		(net "GND")
	)
	(segment
		(start 34.551366 -193.324226)
		(end 35.567366 -193.324226)
		(width 0.3556)
		(layer "B.Cu")
		(net "GND")
	)
	(segment
		(start 250.775216 -107.327192)
		(end 250.775216 -107.178094)
		(width 0.381)
		(layer "B.Cu")
		(net "GND")
	)
	(segment
		(start 13.909548 -113.028222)
		(end 13.400532 -112.519206)
		(width 0.2032)
		(layer "B.Cu")
		(net "GND")
	)
	(segment
		(start 24.345646 -319.344548)
		(end 24.672798 -319.017396)
		(width 0.381)
		(layer "B.Cu")
		(net "GND")
	)
	(segment
		(start 302.749204 -319.468754)
		(end 302.749204 -319.05956)
		(width 0.3556)
		(layer "B.Cu")
		(net "GND")
	)
	(segment
		(start 160.43783 -117.763798)
		(end 160.43783 -117.566948)
		(width 0.3556)
		(layer "B.Cu")
		(net "GND")
	)
	(segment
		(start 155.14828 -333.393288)
		(end 157.17012 -335.415128)
		(width 0.3556)
		(layer "B.Cu")
		(net "GND")
	)
	(segment
		(start 372.299738 -354.89388)
		(end 371.944138 -354.53828)
		(width 0.3556)
		(layer "B.Cu")
		(net "GND")
	)
	(segment
		(start 123.299982 -270.693134)
		(end 123.310396 -270.687038)
		(width 0.0889)
		(layer "B.Cu")
		(net "GND")
	)
	(segment
		(start 299.6946 -343.760044)
		(end 299.6946 -344.700352)
		(width 0.508)
		(layer "B.Cu")
		(net "GND")
	)
	(segment
		(start 283.430726 -194.280536)
		(end 283.916882 -194.766692)
		(width 0.3556)
		(layer "B.Cu")
		(net "GND")
	)
	(segment
		(start 164.24783 -122.646948)
		(end 163.63823 -122.646948)
		(width 0.3556)
		(layer "B.Cu")
		(net "GND")
	)
	(segment
		(start 229.37978 -125.440948)
		(end 228.88194 -125.938788)
		(width 0.3556)
		(layer "B.Cu")
		(net "GND")
	)
	(segment
		(start 314.092082 -230.466646)
		(end 314.126626 -230.50119)
		(width 0.3556)
		(layer "B.Cu")
		(net "GND")
	)
	(segment
		(start 119.521986 -270.704056)
		(end 119.551196 -270.687038)
		(width 0.0889)
		(layer "B.Cu")
		(net "GND")
	)
	(segment
		(start 374.4214 -186.858148)
		(end 374.821196 -186.858148)
		(width 0.3556)
		(layer "B.Cu")
		(net "GND")
	)
	(segment
		(start 306.500022 -30.724348)
		(end 306.963572 -30.724348)
		(width 0.3556)
		(layer "B.Cu")
		(net "GND")
	)
	(segment
		(start 444.885064 -319.263776)
		(end 444.966344 -319.345056)
		(width 0.3556)
		(layer "B.Cu")
		(net "GND")
	)
	(segment
		(start 406.70226 -380.507748)
		(end 404.92172 -382.288288)
		(width 0.3556)
		(layer "B.Cu")
		(net "GND")
	)
	(segment
		(start 309.100982 -319.400174)
		(end 309.47741 -319.776602)
		(width 0.3556)
		(layer "B.Cu")
		(net "GND")
	)
	(segment
		(start 245.435374 -100.121212)
		(end 245.435374 -99.136708)
		(width 0.381)
		(layer "B.Cu")
		(net "GND")
	)
	(segment
		(start 431.22215 -51.42738)
		(end 431.98034 -50.66919)
		(width 0.3556)
		(layer "B.Cu")
		(net "GND")
	)
	(segment
		(start 129.54762 -19.916648)
		(end 129.1463 -19.916648)
		(width 0.3556)
		(layer "B.Cu")
		(net "GND")
	)
	(segment
		(start 279.119584 -190.409576)
		(end 279.119584 -193.269616)
		(width 0.3556)
		(layer "B.Cu")
		(net "GND")
	)
	(segment
		(start 259.097526 -76.958952)
		(end 260.121146 -76.958952)
		(width 0.3556)
		(layer "B.Cu")
		(net "GND")
	)
	(segment
		(start 157.399482 -319.363344)
		(end 158.297118 -319.363344)
		(width 0.3556)
		(layer "B.Cu")
		(net "GND")
	)
	(segment
		(start 297.265598 -154.261058)
		(end 295.873932 -154.261058)
		(width 0.3556)
		(layer "B.Cu")
		(net "GND")
	)
	(segment
		(start 121.11736 -355.194108)
		(end 120.72239 -354.799138)
		(width 0.3556)
		(layer "B.Cu")
		(net "GND")
	)
	(segment
		(start 205.446122 -105.20807)
		(end 205.446122 -108.090716)
		(width 0.3556)
		(layer "B.Cu")
		(net "GND")
	)
	(segment
		(start 53.815996 -319.268856)
		(end 54.121558 -319.268856)
		(width 0.381)
		(layer "B.Cu")
		(net "GND")
	)
	(segment
		(start 314.710572 -54.219348)
		(end 314.07608 -54.219348)
		(width 0.3556)
		(layer "B.Cu")
		(net "GND")
	)
	(segment
		(start 164.24783 -118.836948)
		(end 163.63188 -118.836948)
		(width 0.3556)
		(layer "B.Cu")
		(net "GND")
	)
	(segment
		(start 161.57956 -336.263488)
		(end 161.57956 -353.347528)
		(width 0.3556)
		(layer "B.Cu")
		(net "GND")
	)
	(segment
		(start 448.828922 -50.174144)
		(end 449.52666 -49.476406)
		(width 0.508)
		(layer "B.Cu")
		(net "GND")
	)
	(segment
		(start 129.1463 -19.916648)
		(end 128.85674 -20.206208)
		(width 0.3556)
		(layer "B.Cu")
		(net "GND")
	)
	(segment
		(start 126.89586 -22.394418)
		(end 126.238508 -22.394418)
		(width 0.3556)
		(layer "B.Cu")
		(net "GND")
	)
	(segment
		(start 63.687452 -15.403068)
		(end 62.73546 -15.403068)
		(width 0.3556)
		(layer "B.Cu")
		(net "GND")
	)
	(segment
		(start 170.965622 -335.477612)
		(end 171.981622 -335.477612)
		(width 0.508)
		(layer "B.Cu")
		(net "GND")
	)
	(segment
		(start 384.312414 -271.500854)
		(end 384.327146 -271.50949)
		(width 0.0889)
		(layer "B.Cu")
		(net "GND")
	)
	(segment
		(start 383.453132 -270.695674)
		(end 383.467864 -270.687038)
		(width 0.0889)
		(layer "B.Cu")
		(net "GND")
	)
	(segment
		(start 435.145942 -9.09701)
		(end 435.145942 -8.717026)
		(width 0.3556)
		(layer "B.Cu")
		(net "GND")
	)
	(segment
		(start 334.094074 -49.645062)
		(end 334.13192 -49.607216)
		(width 0.381)
		(layer "B.Cu")
		(net "GND")
	)
	(segment
		(start 372.175532 -270.695674)
		(end 372.190264 -270.687038)
		(width 0.0889)
		(layer "B.Cu")
		(net "GND")
	)
	(segment
		(start 75.071478 -196.12229)
		(end 75.071478 -200.99655)
		(width 0.3556)
		(layer "B.Cu")
		(net "GND")
	)
	(segment
		(start 286.891476 -319.486788)
		(end 286.668464 -319.263776)
		(width 0.3048)
		(layer "B.Cu")
		(net "GND")
	)
	(segment
		(start 367.378488 -189.92342)
		(end 367.852198 -190.39713)
		(width 0.3556)
		(layer "B.Cu")
		(net "GND")
	)
	(segment
		(start 423.250106 -319.357502)
		(end 423.250106 -318.781176)
		(width 0.3556)
		(layer "B.Cu")
		(net "GND")
	)
	(segment
		(start 213.18093 -318.784478)
		(end 213.295484 -318.669924)
		(width 0.381)
		(layer "B.Cu")
		(net "GND")
	)
	(segment
		(start 341.125048 -52.480972)
		(end 341.253318 -52.480972)
		(width 0.381)
		(layer "B.Cu")
		(net "GND")
	)
	(segment
		(start 414.161478 -344.010996)
		(end 415.101786 -344.010996)
		(width 0.508)
		(layer "B.Cu")
		(net "GND")
	)
	(segment
		(start 71.167498 -204.90053)
		(end 71.167498 -206.38897)
		(width 0.3556)
		(layer "B.Cu")
		(net "GND")
	)
	(segment
		(start 129.874264 -270.695674)
		(end 129.888996 -270.687038)
		(width 0.0889)
		(layer "B.Cu")
		(net "GND")
	)
	(segment
		(start 312.090816 -27.720798)
		(end 312.090816 -28.478988)
		(width 0.3556)
		(layer "B.Cu")
		(net "GND")
	)
	(segment
		(start 272.285714 -319.344548)
		(end 272.549366 -319.080896)
		(width 0.254)
		(layer "B.Cu")
		(net "GND")
	)
	(segment
		(start 167.461946 -246.616728)
		(end 167.082216 -246.616728)
		(width 0.381)
		(layer "B.Cu")
		(net "GND")
	)
	(segment
		(start 126.115064 -270.695674)
		(end 126.129796 -270.687038)
		(width 0.0889)
		(layer "B.Cu")
		(net "GND")
	)
	(segment
		(start 369.356132 -270.695674)
		(end 369.370864 -270.687038)
		(width 0.0889)
		(layer "B.Cu")
		(net "GND")
	)
	(segment
		(start 222.484188 -96.467422)
		(end 224.401888 -97.25914)
		(width 0.254)
		(layer "B.Cu")
		(net "GND")
	)
	(segment
		(start 152.72004 -272.793968)
		(end 154.51836 -272.793968)
		(width 0.3556)
		(layer "B.Cu")
		(net "GND")
	)
	(segment
		(start 380.43358 -186.055508)
		(end 380.75108 -185.738008)
		(width 0.3556)
		(layer "B.Cu")
		(net "GND")
	)
	(segment
		(start 287.384236 -319.63741)
		(end 287.384236 -319.351914)
		(width 0.3048)
		(layer "B.Cu")
		(net "GND")
	)
	(segment
		(start 185.755788 -109.375448)
		(end 185.9026 -109.375448)
		(width 0.3556)
		(layer "B.Cu")
		(net "GND")
	)
	(segment
		(start 421.292528 -343.077038)
		(end 421.292528 -344.017346)
		(width 0.508)
		(layer "B.Cu")
		(net "GND")
	)
	(segment
		(start 229.87254 -125.787404)
		(end 229.87254 -125.440948)
		(width 0.3556)
		(layer "B.Cu")
		(net "GND")
	)
	(segment
		(start 189.439804 -319.450974)
		(end 189.621922 -319.268856)
		(width 0.381)
		(layer "B.Cu")
		(net "GND")
	)
	(segment
		(start 52.730908 -192.85966)
		(end 52.730908 -192.24117)
		(width 0.381)
		(layer "B.Cu")
		(net "GND")
	)
	(segment
		(start 367.89868 -362.858304)
		(end 369.769898 -360.987086)
		(width 0.3556)
		(layer "B.Cu")
		(net "GND")
	)
	(segment
		(start 212.209634 -92.202762)
		(end 214.155782 -93.004132)
		(width 0.254)
		(layer "B.Cu")
		(net "GND")
	)
	(segment
		(start 123.249944 -360.132376)
		(end 123.617736 -359.764584)
		(width 0.3556)
		(layer "B.Cu")
		(net "GND")
	)
	(segment
		(start 376.874532 -270.695674)
		(end 376.889264 -270.687038)
		(width 0.0889)
		(layer "B.Cu")
		(net "GND")
	)
	(segment
		(start 39.221156 -318.366648)
		(end 39.221156 -318.733678)
		(width 0.3556)
		(layer "B.Cu")
		(net "GND")
	)
	(segment
		(start 209.394806 -194.136264)
		(end 208.900268 -193.641726)
		(width 0.3556)
		(layer "B.Cu")
		(net "GND")
	)
	(segment
		(start 68.661788 -188.012578)
		(end 68.29298 -188.381386)
		(width 0.3556)
		(layer "B.Cu")
		(net "GND")
	)
	(segment
		(start 375.934732 -270.695674)
		(end 375.949464 -270.687038)
		(width 0.0889)
		(layer "B.Cu")
		(net "GND")
	)
	(segment
		(start 154.549602 -101.637846)
		(end 156.180028 -101.637846)
		(width 0.3556)
		(layer "B.Cu")
		(net "GND")
	)
	(segment
		(start 331.01788 -25.974548)
		(end 330.73848 -25.695148)
		(width 0.3556)
		(layer "B.Cu")
		(net "GND")
	)
	(segment
		(start 369.769898 -360.987086)
		(end 369.769898 -360.335576)
		(width 0.3556)
		(layer "B.Cu")
		(net "GND")
	)
	(segment
		(start 426.54982 -344.017346)
		(end 427.490128 -344.017346)
		(width 0.508)
		(layer "B.Cu")
		(net "GND")
	)
	(segment
		(start 204.488796 -319.268856)
		(end 204.666596 -319.446656)
		(width 0.381)
		(layer "B.Cu")
		(net "GND")
	)
	(segment
		(start 20.566634 -176.823624)
		(end 19.588734 -176.823624)
		(width 0.381)
		(layer "B.Cu")
		(net "GND")
	)
	(segment
		(start 405.648414 -195.616576)
		(end 405.301958 -195.27012)
		(width 0.3556)
		(layer "B.Cu")
		(net "GND")
	)
	(segment
		(start 238.236252 -126.520956)
		(end 238.244126 -126.513082)
		(width 0.3556)
		(layer "B.Cu")
		(net "GND")
	)
	(segment
		(start 187.273946 -194.492118)
		(end 187.174886 -194.393058)
		(width 0.3556)
		(layer "B.Cu")
		(net "GND")
	)
	(segment
		(start 43.47972 -102.07879)
		(end 42.814748 -101.413818)
		(width 0.3556)
		(layer "B.Cu")
		(net "GND")
	)
	(segment
		(start 188.190886 -193.999866)
		(end 187.174886 -193.999866)
		(width 0.3556)
		(layer "B.Cu")
		(net "GND")
	)
	(segment
		(start 294.212264 -319.263776)
		(end 294.421052 -319.263776)
		(width 0.3556)
		(layer "B.Cu")
		(net "GND")
	)
	(segment
		(start 179.259992 -107.07116)
		(end 179.35575 -106.975402)
		(width 0.3556)
		(layer "B.Cu")
		(net "GND")
	)
	(segment
		(start 131.753864 -270.695674)
		(end 131.768596 -270.687038)
		(width 0.0889)
		(layer "B.Cu")
		(net "GND")
	)
	(segment
		(start 169.949622 -335.477612)
		(end 170.965622 -335.477612)
		(width 0.508)
		(layer "B.Cu")
		(net "GND")
	)
	(segment
		(start 431.52568 -177.206148)
		(end 431.975768 -176.75606)
		(width 0.3556)
		(layer "B.Cu")
		(net "GND")
	)
	(segment
		(start 121.416064 -270.695674)
		(end 121.430796 -270.687038)
		(width 0.0889)
		(layer "B.Cu")
		(net "GND")
	)
	(segment
		(start 432.83378 -48.9331)
		(end 434.218334 -48.9331)
		(width 0.3556)
		(layer "B.Cu")
		(net "GND")
	)
	(segment
		(start 190.599822 -319.301876)
		(end 190.63335 -319.268348)
		(width 0.3556)
		(layer "B.Cu")
		(net "GND")
	)
	(segment
		(start 430.577752 -319.294256)
		(end 430.768506 -319.103502)
		(width 0.3556)
		(layer "B.Cu")
		(net "GND")
	)
	(segment
		(start 39.3954 -437.046878)
		(end 39.3954 -437.708548)
		(width 0.3556)
		(layer "B.Cu")
		(net "GND")
	)
	(segment
		(start 358.51719 -360.847386)
		(end 358.42321 -360.753406)
		(width 0.381)
		(layer "B.Cu")
		(net "GND")
	)
	(segment
		(start 249.87504 -107.770168)
		(end 250.33224 -107.770168)
		(width 0.381)
		(layer "B.Cu")
		(net "GND")
	)
	(segment
		(start 229.87254 -125.440948)
		(end 229.37978 -125.440948)
		(width 0.3556)
		(layer "B.Cu")
		(net "GND")
	)
	(segment
		(start 205.170532 -318.883792)
		(end 205.170532 -318.392048)
		(width 0.381)
		(layer "B.Cu")
		(net "GND")
	)
	(segment
		(start 24.327866 -193.552826)
		(end 25.343866 -193.552826)
		(width 0.3556)
		(layer "B.Cu")
		(net "GND")
	)
	(segment
		(start 307.521864 -316.906402)
		(end 307.16601 -316.906402)
		(width 0.3556)
		(layer "B.Cu")
		(net "GND")
	)
	(segment
		(start 167.524684 -319.446656)
		(end 167.346884 -319.268856)
		(width 0.381)
		(layer "B.Cu")
		(net "GND")
	)
	(segment
		(start 121.830084 -361.133136)
		(end 121.830084 -360.345736)
		(width 0.3556)
		(layer "B.Cu")
		(net "GND")
	)
	(segment
		(start 139.50569 -30.557978)
		(end 138.77798 -30.557978)
		(width 0.3556)
		(layer "B.Cu")
		(net "GND")
	)
	(segment
		(start 420.282116 -137.178034)
		(end 419.590474 -137.178034)
		(width 0.381)
		(layer "B.Cu")
		(net "GND")
	)
	(segment
		(start 408.01417 -318.755776)
		(end 408.797506 -318.755776)
		(width 0.3556)
		(layer "B.Cu")
		(net "GND")
	)
	(segment
		(start 110.483396 -360.753406)
		(end 110.577376 -360.847386)
		(width 0.381)
		(layer "B.Cu")
		(net "GND")
	)
	(segment
		(start 197.496684 -319.345056)
		(end 197.699884 -319.345056)
		(width 0.381)
		(layer "B.Cu")
		(net "GND")
	)
	(segment
		(start 54.121558 -319.268856)
		(end 54.565296 -319.712594)
		(width 0.381)
		(layer "B.Cu")
		(net "GND")
	)
	(segment
		(start 383.84226 -270.687038)
		(end 383.85115 -270.692118)
		(width 0.0889)
		(layer "B.Cu")
		(net "GND")
	)
	(segment
		(start 371.944138 -354.53828)
		(end 371.665246 -354.53828)
		(width 0.3556)
		(layer "B.Cu")
		(net "GND")
	)
	(segment
		(start 298.754292 -344.700352)
		(end 299.6946 -344.700352)
		(width 0.508)
		(layer "B.Cu")
		(net "GND")
	)
	(segment
		(start 8.553196 -319.268856)
		(end 9.182354 -319.268856)
		(width 0.3556)
		(layer "B.Cu")
		(net "GND")
	)
	(segment
		(start 184.155588 -105.375456)
		(end 184.155588 -105.223056)
		(width 0.3556)
		(layer "B.Cu")
		(net "GND")
	)
	(segment
		(start 139.346686 -8.962898)
		(end 139.346686 -8.255)
		(width 0.3556)
		(layer "B.Cu")
		(net "GND")
	)
	(segment
		(start 137.312146 -271.500854)
		(end 137.326878 -271.50949)
		(width 0.0889)
		(layer "B.Cu")
		(net "GND")
	)
	(segment
		(start 233.761788 -252.279658)
		(end 233.5022 -252.279658)
		(width 0.3556)
		(layer "B.Cu")
		(net "GND")
	)
	(arc
		(start 129.888996 -270.687038)
		(mid 130.076194 -270.636895)
		(end 130.263392 -270.687038)
		(width 0.0889)
		(layer "B.Cu")
		(net "GND")
	)
	(arc
		(start 384.877818 -271.500854)
		(mid 385.065016 -271.450711)
		(end 385.252214 -271.500854)
		(width 0.0889)
		(layer "B.Cu")
		(net "GND")
	)
	(arc
		(start 377.26366 -270.687038)
		(mid 377.537859 -270.762873)
		(end 377.814332 -270.695674)
		(width 0.0889)
		(layer "B.Cu")
		(net "GND")
	)
	(arc
		(start 380.08306 -270.687038)
		(mid 380.357259 -270.762873)
		(end 380.633732 -270.695674)
		(width 0.0889)
		(layer "B.Cu")
		(net "GND")
	)
	(arc
		(start 130.263392 -270.687038)
		(mid 130.537591 -270.762873)
		(end 130.814064 -270.695674)
		(width 0.0889)
		(layer "B.Cu")
		(net "GND")
	)
	(arc
		(start 131.203192 -270.687038)
		(mid 131.477391 -270.762873)
		(end 131.753864 -270.695674)
		(width 0.0889)
		(layer "B.Cu")
		(net "GND")
	)
	(arc
		(start 134.962392 -270.687038)
		(mid 135.236591 -270.762873)
		(end 135.513064 -270.695674)
		(width 0.0889)
		(layer "B.Cu")
		(net "GND")
	)
	(arc
		(start 132.708396 -270.687038)
		(mid 132.895594 -270.636895)
		(end 133.082792 -270.687038)
		(width 0.0889)
		(layer "B.Cu")
		(net "GND")
	)
	(arc
		(start 119.551196 -270.687038)
		(mid 119.738394 -270.636895)
		(end 119.925592 -270.687038)
		(width 0.0889)
		(layer "B.Cu")
		(net "GND")
	)
	(arc
		(start 368.431064 -270.687038)
		(mid 368.618262 -270.636895)
		(end 368.80546 -270.687038)
		(width 0.0889)
		(layer "B.Cu")
		(net "GND")
	)
	(arc
		(start 137.029444 -271.02689)
		(mid 137.108814 -271.300624)
		(end 137.311638 -271.500854)
		(width 0.0889)
		(layer "B.Cu")
		(net "GND")
	)
	(arc
		(start 382.90246 -270.687038)
		(mid 383.176659 -270.762873)
		(end 383.453132 -270.695674)
		(width 0.0889)
		(layer "B.Cu")
		(net "GND")
	)
	(arc
		(start 119.925592 -270.687038)
		(mid 120.199791 -270.762873)
		(end 120.476264 -270.695674)
		(width 0.0889)
		(layer "B.Cu")
		(net "GND")
	)
	(arc
		(start 123.684792 -270.687038)
		(mid 123.958991 -270.762873)
		(end 124.235464 -270.695674)
		(width 0.0889)
		(layer "B.Cu")
		(net "GND")
	)
	(arc
		(start 131.768596 -270.687038)
		(mid 131.955794 -270.636895)
		(end 132.142992 -270.687038)
		(width 0.0889)
		(layer "B.Cu")
		(net "GND")
	)
	(arc
		(start 371.250464 -270.687038)
		(mid 371.437662 -270.636895)
		(end 371.62486 -270.687038)
		(width 0.0889)
		(layer "B.Cu")
		(net "GND")
	)
	(arc
		(start 385.266946 -271.50949)
		(mid 385.543421 -271.57681)
		(end 385.817618 -271.500854)
		(width 0.0889)
		(layer "B.Cu")
		(net "GND")
	)
	(arc
		(start 133.082792 -270.687038)
		(mid 133.365494 -270.762814)
		(end 133.648196 -270.687038)
		(width 0.0889)
		(layer "B.Cu")
		(net "GND")
	)
	(arc
		(start 374.069864 -270.687038)
		(mid 374.257062 -270.636895)
		(end 374.44426 -270.687038)
		(width 0.0889)
		(layer "B.Cu")
		(net "GND")
	)
	(arc
		(start 126.504192 -270.687038)
		(mid 126.778391 -270.762873)
		(end 127.054864 -270.695674)
		(width 0.0889)
		(layer "B.Cu")
		(net "GND")
	)
	(arc
		(start 368.80546 -270.687038)
		(mid 369.079659 -270.762873)
		(end 369.356132 -270.695674)
		(width 0.0889)
		(layer "B.Cu")
		(net "GND")
	)
	(arc
		(start 370.685314 -270.687038)
		(mid 370.961873 -270.762781)
		(end 371.24005 -270.693134)
		(width 0.0889)
		(layer "B.Cu")
		(net "GND")
	)
	(arc
		(start 124.250196 -270.687038)
		(mid 124.437394 -270.636895)
		(end 124.624592 -270.687038)
		(width 0.0889)
		(layer "B.Cu")
		(net "GND")
	)
	(arc
		(start 367.86566 -270.687038)
		(mid 368.139859 -270.762873)
		(end 368.416332 -270.695674)
		(width 0.0889)
		(layer "B.Cu")
		(net "GND")
	)
	(arc
		(start 372.190264 -270.687038)
		(mid 372.377462 -270.636895)
		(end 372.56466 -270.687038)
		(width 0.0889)
		(layer "B.Cu")
		(net "GND")
	)
	(arc
		(start 370.310918 -270.687038)
		(mid 370.498116 -270.636895)
		(end 370.685314 -270.687038)
		(width 0.0889)
		(layer "B.Cu")
		(net "GND")
	)
	(arc
		(start 120.490996 -270.687038)
		(mid 120.678194 -270.636895)
		(end 120.865392 -270.687038)
		(width 0.0889)
		(layer "B.Cu")
		(net "GND")
	)
	(arc
		(start 127.443992 -270.687038)
		(mid 127.718191 -270.762873)
		(end 127.994664 -270.695674)
		(width 0.0889)
		(layer "B.Cu")
		(net "GND")
	)
	(arc
		(start 121.805192 -270.687038)
		(mid 122.082005 -270.762908)
		(end 122.360436 -270.693134)
		(width 0.0889)
		(layer "B.Cu")
		(net "GND")
	)
	(arc
		(start 125.189996 -270.687038)
		(mid 125.377194 -270.636895)
		(end 125.564392 -270.687038)
		(width 0.0889)
		(layer "B.Cu")
		(net "GND")
	)
	(arc
		(start 376.889264 -270.687038)
		(mid 377.076462 -270.636895)
		(end 377.26366 -270.687038)
		(width 0.0889)
		(layer "B.Cu")
		(net "GND")
	)
	(arc
		(start 135.527796 -270.687038)
		(mid 135.714994 -270.636895)
		(end 135.902192 -270.687038)
		(width 0.0889)
		(layer "B.Cu")
		(net "GND")
	)
	(arc
		(start 380.648464 -270.687038)
		(mid 380.835662 -270.636895)
		(end 381.02286 -270.687038)
		(width 0.0889)
		(layer "B.Cu")
		(net "GND")
	)
	(arc
		(start 132.142992 -270.687038)
		(mid 132.417191 -270.762873)
		(end 132.693664 -270.695674)
		(width 0.0889)
		(layer "B.Cu")
		(net "GND")
	)
	(arc
		(start 374.44426 -270.687038)
		(mid 374.718459 -270.762873)
		(end 374.994932 -270.695674)
		(width 0.0889)
		(layer "B.Cu")
		(net "GND")
	)
	(arc
		(start 128.009396 -270.687038)
		(mid 128.196594 -270.636895)
		(end 128.383792 -270.687038)
		(width 0.0889)
		(layer "B.Cu")
		(net "GND")
	)
	(arc
		(start 381.02286 -270.687038)
		(mid 381.305562 -270.762814)
		(end 381.588264 -270.687038)
		(width 0.0889)
		(layer "B.Cu")
		(net "GND")
	)
	(arc
		(start 124.624592 -270.687038)
		(mid 124.898791 -270.762873)
		(end 125.175264 -270.695674)
		(width 0.0889)
		(layer "B.Cu")
		(net "GND")
	)
	(arc
		(start 383.85115 -270.692118)
		(mid 383.982064 -270.828478)
		(end 384.029712 -271.011396)
		(width 0.0889)
		(layer "B.Cu")
		(net "GND")
	)
	(arc
		(start 381.588264 -270.687038)
		(mid 381.775462 -270.636895)
		(end 381.96266 -270.687038)
		(width 0.0889)
		(layer "B.Cu")
		(net "GND")
	)
	(arc
		(start 125.564392 -270.687038)
		(mid 125.838591 -270.762873)
		(end 126.115064 -270.695674)
		(width 0.0889)
		(layer "B.Cu")
		(net "GND")
	)
	(arc
		(start 377.829064 -270.687038)
		(mid 378.016262 -270.636895)
		(end 378.20346 -270.687038)
		(width 0.0889)
		(layer "B.Cu")
		(net "GND")
	)
	(arc
		(start 120.865392 -270.687038)
		(mid 121.139591 -270.762873)
		(end 121.416064 -270.695674)
		(width 0.0889)
		(layer "B.Cu")
		(net "GND")
	)
	(arc
		(start 133.648196 -270.687038)
		(mid 133.835394 -270.636895)
		(end 134.022592 -270.687038)
		(width 0.0889)
		(layer "B.Cu")
		(net "GND")
	)
	(arc
		(start 136.850882 -270.692118)
		(mid 136.981796 -270.828478)
		(end 137.029444 -271.011396)
		(width 0.0889)
		(layer "B.Cu")
		(net "GND")
	)
	(arc
		(start 385.817618 -271.500854)
		(mid 386.004816 -271.450711)
		(end 386.192014 -271.500854)
		(width 0.0889)
		(layer "B.Cu")
		(net "GND")
	)
	(arc
		(start 136.467596 -270.687038)
		(mid 136.654794 -270.636895)
		(end 136.841992 -270.687038)
		(width 0.0889)
		(layer "B.Cu")
		(net "GND")
	)
	(arc
		(start 127.069596 -270.687038)
		(mid 127.256794 -270.636895)
		(end 127.443992 -270.687038)
		(width 0.0889)
		(layer "B.Cu")
		(net "GND")
	)
	(arc
		(start 137.326878 -271.50949)
		(mid 137.603353 -271.57681)
		(end 137.87755 -271.500854)
		(width 0.0889)
		(layer "B.Cu")
		(net "GND")
	)
	(arc
		(start 381.96266 -270.687038)
		(mid 382.236859 -270.762873)
		(end 382.513332 -270.695674)
		(width 0.0889)
		(layer "B.Cu")
		(net "GND")
	)
	(arc
		(start 373.130064 -270.687038)
		(mid 373.317262 -270.636895)
		(end 373.50446 -270.687038)
		(width 0.0889)
		(layer "B.Cu")
		(net "GND")
	)
	(arc
		(start 123.310396 -270.687038)
		(mid 123.497594 -270.636895)
		(end 123.684792 -270.687038)
		(width 0.0889)
		(layer "B.Cu")
		(net "GND")
	)
	(arc
		(start 375.38406 -270.687038)
		(mid 375.658259 -270.762873)
		(end 375.934732 -270.695674)
		(width 0.0889)
		(layer "B.Cu")
		(net "GND")
	)
	(arc
		(start 129.323592 -270.687038)
		(mid 129.597791 -270.762873)
		(end 129.874264 -270.695674)
		(width 0.0889)
		(layer "B.Cu")
		(net "GND")
	)
	(arc
		(start 384.327146 -271.50949)
		(mid 384.603621 -271.57681)
		(end 384.877818 -271.500854)
		(width 0.0889)
		(layer "B.Cu")
		(net "GND")
	)
	(arc
		(start 384.029712 -271.011396)
		(mid 384.103703 -271.290962)
		(end 384.306318 -271.497298)
		(width 0.0889)
		(layer "B.Cu")
		(net "GND")
	)
	(arc
		(start 138.266678 -271.50949)
		(mid 138.543153 -271.57681)
		(end 138.81735 -271.500854)
		(width 0.0889)
		(layer "B.Cu")
		(net "GND")
	)
	(arc
		(start 379.708664 -270.687038)
		(mid 379.895862 -270.636895)
		(end 380.08306 -270.687038)
		(width 0.0889)
		(layer "B.Cu")
		(net "GND")
	)
	(arc
		(start 135.902192 -270.687038)
		(mid 136.176391 -270.762873)
		(end 136.452864 -270.695674)
		(width 0.0889)
		(layer "B.Cu")
		(net "GND")
	)
	(arc
		(start 130.828796 -270.687038)
		(mid 131.015994 -270.636895)
		(end 131.203192 -270.687038)
		(width 0.0889)
		(layer "B.Cu")
		(net "GND")
	)
	(arc
		(start 376.32386 -270.687038)
		(mid 376.598059 -270.762873)
		(end 376.874532 -270.695674)
		(width 0.0889)
		(layer "B.Cu")
		(net "GND")
	)
	(arc
		(start 378.768864 -270.687038)
		(mid 378.956062 -270.636895)
		(end 379.14326 -270.687038)
		(width 0.0889)
		(layer "B.Cu")
		(net "GND")
	)
	(arc
		(start 122.37085 -270.687038)
		(mid 122.558048 -270.636895)
		(end 122.745246 -270.687038)
		(width 0.0889)
		(layer "B.Cu")
		(net "GND")
	)
	(arc
		(start 128.949196 -270.687038)
		(mid 129.136394 -270.636895)
		(end 129.323592 -270.687038)
		(width 0.0889)
		(layer "B.Cu")
		(net "GND")
	)
	(arc
		(start 367.491264 -270.687038)
		(mid 367.678462 -270.636895)
		(end 367.86566 -270.687038)
		(width 0.0889)
		(layer "B.Cu")
		(net "GND")
	)
	(arc
		(start 134.022592 -270.687038)
		(mid 134.296791 -270.762873)
		(end 134.573264 -270.695674)
		(width 0.0889)
		(layer "B.Cu")
		(net "GND")
	)
	(arc
		(start 369.74526 -270.687038)
		(mid 370.022073 -270.762908)
		(end 370.300504 -270.693134)
		(width 0.0889)
		(layer "B.Cu")
		(net "GND")
	)
	(arc
		(start 121.430796 -270.687038)
		(mid 121.617994 -270.636895)
		(end 121.805192 -270.687038)
		(width 0.0889)
		(layer "B.Cu")
		(net "GND")
	)
	(arc
		(start 382.528064 -270.687038)
		(mid 382.715262 -270.636895)
		(end 382.90246 -270.687038)
		(width 0.0889)
		(layer "B.Cu")
		(net "GND")
	)
	(arc
		(start 378.20346 -270.687038)
		(mid 378.477659 -270.762873)
		(end 378.754132 -270.695674)
		(width 0.0889)
		(layer "B.Cu")
		(net "GND")
	)
	(arc
		(start 386.206746 -271.50949)
		(mid 386.483221 -271.57681)
		(end 386.757418 -271.500854)
		(width 0.0889)
		(layer "B.Cu")
		(net "GND")
	)
	(arc
		(start 128.383792 -270.687038)
		(mid 128.657991 -270.762873)
		(end 128.934464 -270.695674)
		(width 0.0889)
		(layer "B.Cu")
		(net "GND")
	)
	(arc
		(start 383.467864 -270.687038)
		(mid 383.655062 -270.636895)
		(end 383.84226 -270.687038)
		(width 0.0889)
		(layer "B.Cu")
		(net "GND")
	)
	(arc
		(start 373.50446 -270.687038)
		(mid 373.778659 -270.762873)
		(end 374.055132 -270.695674)
		(width 0.0889)
		(layer "B.Cu")
		(net "GND")
	)
	(arc
		(start 138.81735 -271.500854)
		(mid 138.907606 -271.463132)
		(end 139.004548 -271.450054)
		(width 0.0889)
		(layer "B.Cu")
		(net "GND")
	)
	(arc
		(start 386.757418 -271.500854)
		(mid 386.847674 -271.463132)
		(end 386.944616 -271.450054)
		(width 0.0889)
		(layer "B.Cu")
		(net "GND")
	)
	(arc
		(start 371.62486 -270.687038)
		(mid 371.899059 -270.762873)
		(end 372.175532 -270.695674)
		(width 0.0889)
		(layer "B.Cu")
		(net "GND")
	)
	(arc
		(start 126.129796 -270.687038)
		(mid 126.316994 -270.636895)
		(end 126.504192 -270.687038)
		(width 0.0889)
		(layer "B.Cu")
		(net "GND")
	)
	(arc
		(start 122.745246 -270.687038)
		(mid 123.021805 -270.762781)
		(end 123.299982 -270.693134)
		(width 0.0889)
		(layer "B.Cu")
		(net "GND")
	)
	(arc
		(start 375.949464 -270.687038)
		(mid 376.136662 -270.636895)
		(end 376.32386 -270.687038)
		(width 0.0889)
		(layer "B.Cu")
		(net "GND")
	)
	(arc
		(start 379.14326 -270.687038)
		(mid 379.417459 -270.762873)
		(end 379.693932 -270.695674)
		(width 0.0889)
		(layer "B.Cu")
		(net "GND")
	)
	(arc
		(start 375.009664 -270.687038)
		(mid 375.196862 -270.636895)
		(end 375.38406 -270.687038)
		(width 0.0889)
		(layer "B.Cu")
		(net "GND")
	)
	(arc
		(start 134.587996 -270.687038)
		(mid 134.775194 -270.636895)
		(end 134.962392 -270.687038)
		(width 0.0889)
		(layer "B.Cu")
		(net "GND")
	)
	(arc
		(start 137.87755 -271.500854)
		(mid 138.064748 -271.450711)
		(end 138.251946 -271.500854)
		(width 0.0889)
		(layer "B.Cu")
		(net "GND")
	)
	(arc
		(start 372.56466 -270.687038)
		(mid 372.838859 -270.762873)
		(end 373.115332 -270.695674)
		(width 0.0889)
		(layer "B.Cu")
		(net "GND")
	)
	(arc
		(start 369.370864 -270.687038)
		(mid 369.558062 -270.636895)
		(end 369.74526 -270.687038)
		(width 0.0889)
		(layer "B.Cu")
		(net "GND")
	)
	(segment
		(start 279.5778 -70.050152)
		(end 280.423112 -70.895464)
		(width 0.508)
		(layer "In2.Cu")
		(net "GND")
	)
	(segment
		(start 381.053086 -366.338358)
		(end 381.750824 -365.64062)
		(width 0.381)
		(layer "In2.Cu")
		(net "GND")
	)
	(segment
		(start 279.5778 -70.050152)
		(end 280.423112 -69.20484)
		(width 0.508)
		(layer "In2.Cu")
		(net "GND")
	)
	(segment
		(start 279.6032 -63.877952)
		(end 280.27884 -63.202312)
		(width 0.508)
		(layer "In2.Cu")
		(net "GND")
	)
	(segment
		(start 279.6032 -63.877952)
		(end 280.448512 -64.723264)
		(width 0.508)
		(layer "In2.Cu")
		(net "GND")
	)
	(segment
		(start 381.053086 -364.942882)
		(end 381.750824 -365.64062)
		(width 0.381)
		(layer "In2.Cu")
		(net "GND")
	)
	(segment
		(start 381.750824 -365.64062)
		(end 382.448562 -366.338358)
		(width 0.381)
		(layer "In2.Cu")
		(net "GND")
	)
	(segment
		(start 278.732488 -70.895464)
		(end 279.5778 -70.050152)
		(width 0.508)
		(layer "In2.Cu")
		(net "GND")
	)
	(segment
		(start 381.750824 -365.64062)
		(end 382.448562 -364.942882)
		(width 0.381)
		(layer "In2.Cu")
		(net "GND")
	)
	(segment
		(start 278.732488 -69.20484)
		(end 279.5778 -70.050152)
		(width 0.508)
		(layer "In2.Cu")
		(net "GND")
	)
	(segment
		(start 278.757888 -63.03264)
		(end 279.6032 -63.877952)
		(width 0.508)
		(layer "In2.Cu")
		(net "GND")
	)
	(segment
		(start 278.757888 -64.723264)
		(end 279.6032 -63.877952)
		(width 0.508)
		(layer "In2.Cu")
		(net "GND")
	)
	(segment
		(start 133.027674 -366.445546)
		(end 133.725412 -365.747808)
		(width 0.381)
		(layer "In4.Cu")
		(net "GND")
	)
	(segment
		(start 133.027674 -365.05007)
		(end 133.725412 -365.747808)
		(width 0.381)
		(layer "In4.Cu")
		(net "GND")
	)
	(segment
		(start 133.725412 -365.747808)
		(end 134.42315 -365.05007)
		(width 0.381)
		(layer "In4.Cu")
		(net "GND")
	)
	(segment
		(start 133.725412 -365.747808)
		(end 134.42315 -366.445546)
		(width 0.381)
		(layer "In4.Cu")
		(net "GND")
	)
	(segment
		(start 208.054956 -31.253176)
		(end 207.72374 -31.584392)
		(width 0.254)
		(layer "In6.Cu")
		(net "GND")
	)
	(segment
		(start 293.497 -344.700352)
		(end 294.212772 -345.416124)
		(width 0.381)
		(layer "In6.Cu")
		(net "GND")
	)
	(segment
		(start 420.576756 -343.301574)
		(end 421.292528 -344.017346)
		(width 0.381)
		(layer "In6.Cu")
		(net "GND")
	)
	(segment
		(start 100.07981 -223.899984)
		(end 100.0887 -223.894904)
		(width 0.0889)
		(layer "In6.Cu")
		(net "GND")
	)
	(segment
		(start 85.699854 -218.285314)
		(end 85.699854 -217.879168)
		(width 0.0889)
		(layer "In6.Cu")
		(net "GND")
	)
	(segment
		(start 90.307414 -219.995496)
		(end 90.297 -220.001592)
		(width 0.0889)
		(layer "In6.Cu")
		(net "GND")
	)
	(segment
		(start 97.745296 -222.445834)
		(end 97.730564 -222.437198)
		(width 0.0889)
		(layer "In6.Cu")
		(net "GND")
	)
	(segment
		(start 68.774056 -191.2747)
		(end 67.47002 -191.2747)
		(width 0.254)
		(layer "In6.Cu")
		(net "GND")
	)
	(segment
		(start 67.47002 -191.2747)
		(end 63.971424 -187.776104)
		(width 0.254)
		(layer "In6.Cu")
		(net "GND")
	)
	(segment
		(start 85.227668 -217.078306)
		(end 85.227668 -216.63406)
		(width 0.0889)
		(layer "In6.Cu")
		(net "GND")
	)
	(segment
		(start 198.823834 -31.222188)
		(end 198.153782 -30.552136)
		(width 0.254)
		(layer "In6.Cu")
		(net "GND")
	)
	(segment
		(start 191.571626 -19.229578)
		(end 191.571626 -19.288506)
		(width 0.254)
		(layer "In6.Cu")
		(net "GND")
	)
	(segment
		(start 208.054956 -29.266642)
		(end 208.054956 -31.253176)
		(width 0.254)
		(layer "In6.Cu")
		(net "GND")
	)
	(segment
		(start 298.633642 -371.758464)
		(end 299.33138 -372.456202)
		(width 0.508)
		(layer "In6.Cu")
		(net "GND")
	)
	(segment
		(start 426.705776 -371.76837)
		(end 427.403514 -371.070632)
		(width 0.508)
		(layer "In6.Cu")
		(net "GND")
	)
	(segment
		(start 299.33138 -372.456202)
		(end 300.029118 -373.15394)
		(width 0.508)
		(layer "In6.Cu")
		(net "GND")
	)
	(segment
		(start 85.522054 -217.559128)
		(end 85.511386 -217.553032)
		(width 0.0889)
		(layer "In6.Cu")
		(net "GND")
	)
	(segment
		(start 299.6946 -344.700352)
		(end 300.410372 -345.416124)
		(width 0.381)
		(layer "In6.Cu")
		(net "GND")
	)
	(segment
		(start 72.544178 -195.044822)
		(end 68.774056 -191.2747)
		(width 0.254)
		(layer "In6.Cu")
		(net "GND")
	)
	(segment
		(start 195.867274 -28.402534)
		(end 196.581522 -29.116782)
		(width 0.254)
		(layer "In6.Cu")
		(net "GND")
	)
	(segment
		(start 97.730564 -222.437198)
		(end 97.695004 -222.416116)
		(width 0.0889)
		(layer "In6.Cu")
		(net "GND")
	)
	(segment
		(start 100.0887 -223.256348)
		(end 100.07981 -223.251268)
		(width 0.0889)
		(layer "In6.Cu")
		(net "GND")
	)
	(segment
		(start 198.826374 -31.222188)
		(end 198.823834 -31.222188)
		(width 0.254)
		(layer "In6.Cu")
		(net "GND")
	)
	(segment
		(start 101.207062 -226.831144)
		(end 101.207062 -226.822508)
		(width 0.0889)
		(layer "In6.Cu")
		(net "GND")
	)
	(segment
		(start 426.774356 -343.301574)
		(end 427.490128 -344.017346)
		(width 0.381)
		(layer "In6.Cu")
		(net "GND")
	)
	(segment
		(start 95.946214 -219.995496)
		(end 95.9358 -220.001592)
		(width 0.0889)
		(layer "In6.Cu")
		(net "GND")
	)
	(segment
		(start 182.534052 -363.113066)
		(end 183.23179 -363.810804)
		(width 0.508)
		(layer "In6.Cu")
		(net "GND")
	)
	(segment
		(start 426.774356 -344.733118)
		(end 427.490128 -344.017346)
		(width 0.381)
		(layer "In6.Cu")
		(net "GND")
	)
	(segment
		(start 176.440592 -334.76819)
		(end 177.156364 -335.483962)
		(width 0.381)
		(layer "In6.Cu")
		(net "GND")
	)
	(segment
		(start 381.750824 -365.64062)
		(end 382.448562 -366.338358)
		(width 0.381)
		(layer "In6.Cu")
		(net "GND")
	)
	(segment
		(start 84.403692 -215.630252)
		(end 78.7146 -209.94116)
		(width 0.254)
		(layer "In6.Cu")
		(net "GND")
	)
	(segment
		(start 195.398136 -26.38933)
		(end 195.398136 -27.301444)
		(width 0.254)
		(layer "In6.Cu")
		(net "GND")
	)
	(segment
		(start 381.053086 -366.338358)
		(end 381.750824 -365.64062)
		(width 0.381)
		(layer "In6.Cu")
		(net "GND")
	)
	(segment
		(start 182.534052 -363.113066)
		(end 183.23179 -362.415328)
		(width 0.508)
		(layer "In6.Cu")
		(net "GND")
	)
	(segment
		(start 287.2994 -344.700352)
		(end 288.015172 -345.416124)
		(width 0.381)
		(layer "In6.Cu")
		(net "GND")
	)
	(segment
		(start 85.227668 -216.63406)
		(end 85.147658 -216.55405)
		(width 0.0889)
		(layer "In6.Cu")
		(net "GND")
	)
	(segment
		(start 87.382858 -219.968318)
		(end 85.699854 -218.285314)
		(width 0.0889)
		(layer "In6.Cu")
		(net "GND")
	)
	(segment
		(start 199.188578 -31.584392)
		(end 198.826374 -31.222188)
		(width 0.254)
		(layer "In6.Cu")
		(net "GND")
	)
	(segment
		(start 420.576756 -344.733118)
		(end 421.292528 -344.017346)
		(width 0.381)
		(layer "In6.Cu")
		(net "GND")
	)
	(segment
		(start 299.33138 -372.456202)
		(end 300.029118 -371.758464)
		(width 0.508)
		(layer "In6.Cu")
		(net "GND")
	)
	(segment
		(start 85.699854 -217.879168)
		(end 85.700616 -217.878406)
		(width 0.0889)
		(layer "In6.Cu")
		(net "GND")
	)
	(segment
		(start 107.881166 -229.272846)
		(end 107.724702 -229.001828)
		(width 0.0889)
		(layer "In6.Cu")
		(net "GND")
	)
	(segment
		(start 194.825112 -23.23846)
		(end 194.825112 -22.48154)
		(width 0.254)
		(layer "In6.Cu")
		(net "GND")
	)
	(segment
		(start 57.540144 -187.776104)
		(end 57.21985 -187.45581)
		(width 0.254)
		(layer "In6.Cu")
		(net "GND")
	)
	(segment
		(start 133.027674 -365.05007)
		(end 133.725412 -365.747808)
		(width 0.381)
		(layer "In6.Cu")
		(net "GND")
	)
	(segment
		(start 414.386014 -343.295224)
		(end 415.101786 -344.010996)
		(width 0.381)
		(layer "In6.Cu")
		(net "GND")
	)
	(segment
		(start 177.156364 -335.483962)
		(end 177.872136 -334.76819)
		(width 0.381)
		(layer "In6.Cu")
		(net "GND")
	)
	(segment
		(start 57.21985 -187.40755)
		(end 55.11673 -185.30443)
		(width 0.254)
		(layer "In6.Cu")
		(net "GND")
	)
	(segment
		(start 99.797616 -224.404936)
		(end 99.797616 -224.373948)
		(width 0.0889)
		(layer "In6.Cu")
		(net "GND")
	)
	(segment
		(start 84.403692 -215.638126)
		(end 84.403692 -215.630252)
		(width 0.254)
		(layer "In6.Cu")
		(net "GND")
	)
	(segment
		(start 292.781228 -345.416124)
		(end 293.497 -344.700352)
		(width 0.381)
		(layer "In6.Cu")
		(net "GND")
	)
	(segment
		(start 101.498654 -227.325682)
		(end 101.483668 -227.317046)
		(width 0.0889)
		(layer "In6.Cu")
		(net "GND")
	)
	(segment
		(start 101.9683 -228.139752)
		(end 101.95941 -228.134672)
		(width 0.0889)
		(layer "In6.Cu")
		(net "GND")
	)
	(segment
		(start 414.386014 -344.726768)
		(end 415.101786 -344.010996)
		(width 0.381)
		(layer "In6.Cu")
		(net "GND")
	)
	(segment
		(start 194.833494 -25.824688)
		(end 195.398136 -26.38933)
		(width 0.254)
		(layer "In6.Cu")
		(net "GND")
	)
	(segment
		(start 191.358012 -18.714212)
		(end 190.103252 -17.459452)
		(width 0.254)
		(layer "In6.Cu")
		(net "GND")
	)
	(segment
		(start 97.447862 -221.98203)
		(end 97.447862 -221.94774)
		(width 0.0889)
		(layer "In6.Cu")
		(net "GND")
	)
	(segment
		(start 176.440592 -336.199734)
		(end 177.156364 -335.483962)
		(width 0.381)
		(layer "In6.Cu")
		(net "GND")
	)
	(segment
		(start 195.867274 -28.394152)
		(end 195.867274 -28.402534)
		(width 0.254)
		(layer "In6.Cu")
		(net "GND")
	)
	(segment
		(start 181.836314 -363.810804)
		(end 182.534052 -363.113066)
		(width 0.508)
		(layer "In6.Cu")
		(net "GND")
	)
	(segment
		(start 23.760938 -176.220882)
		(end 23.760938 -175.83404)
		(width 0.254)
		(layer "In6.Cu")
		(net "GND")
	)
	(segment
		(start 183.353964 -335.483962)
		(end 184.069736 -336.199734)
		(width 0.381)
		(layer "In6.Cu")
		(net "GND")
	)
	(segment
		(start 100.0887 -224.88398)
		(end 100.07981 -224.8789)
		(width 0.0889)
		(layer "In6.Cu")
		(net "GND")
	)
	(segment
		(start 100.737416 -226.027234)
		(end 100.737416 -226.017328)
		(width 0.0889)
		(layer "In6.Cu")
		(net "GND")
	)
	(segment
		(start 191.571626 -19.288506)
		(end 193.641472 -21.358352)
		(width 0.254)
		(layer "In6.Cu")
		(net "GND")
	)
	(segment
		(start 427.490128 -344.017346)
		(end 428.2059 -343.301574)
		(width 0.381)
		(layer "In6.Cu")
		(net "GND")
	)
	(segment
		(start 381.750824 -365.64062)
		(end 382.448562 -364.942882)
		(width 0.381)
		(layer "In6.Cu")
		(net "GND")
	)
	(segment
		(start 97.2693 -221.628462)
		(end 97.26041 -221.623382)
		(width 0.0889)
		(layer "In6.Cu")
		(net "GND")
	)
	(segment
		(start 183.353964 -335.483962)
		(end 184.069736 -334.76819)
		(width 0.381)
		(layer "In6.Cu")
		(net "GND")
	)
	(segment
		(start 298.978828 -345.416124)
		(end 299.6946 -344.700352)
		(width 0.381)
		(layer "In6.Cu")
		(net "GND")
	)
	(segment
		(start 207.72374 -31.584392)
		(end 199.188578 -31.584392)
		(width 0.254)
		(layer "In6.Cu")
		(net "GND")
	)
	(segment
		(start 191.571626 -19.229578)
		(end 191.358012 -18.714212)
		(width 0.254)
		(layer "In6.Cu")
		(net "GND")
	)
	(segment
		(start 22.60727 -177.37455)
		(end 23.760938 -176.220882)
		(width 0.254)
		(layer "In6.Cu")
		(net "GND")
	)
	(segment
		(start 194.825112 -22.48154)
		(end 194.527932 -22.18436)
		(width 0.254)
		(layer "In6.Cu")
		(net "GND")
	)
	(segment
		(start 421.292528 -344.017346)
		(end 422.0083 -344.733118)
		(width 0.381)
		(layer "In6.Cu")
		(net "GND")
	)
	(segment
		(start 197.28942 -29.846524)
		(end 197.28942 -29.839666)
		(width 0.254)
		(layer "In6.Cu")
		(net "GND")
	)
	(segment
		(start 194.82943 -25.385522)
		(end 194.833494 -25.389586)
		(width 0.254)
		(layer "In6.Cu")
		(net "GND")
	)
	(segment
		(start 96.978216 -221.149418)
		(end 96.978216 -221.133924)
		(width 0.0889)
		(layer "In6.Cu")
		(net "GND")
	)
	(segment
		(start 106.203496 -228.957124)
		(end 106.188764 -228.948488)
		(width 0.0889)
		(layer "In6.Cu")
		(net "GND")
	)
	(segment
		(start 96.3295 -220.000576)
		(end 96.32061 -219.995496)
		(width 0.0889)
		(layer "In6.Cu")
		(net "GND")
	)
	(segment
		(start 96.508062 -220.327474)
		(end 96.508062 -220.319854)
		(width 0.0889)
		(layer "In6.Cu")
		(net "GND")
	)
	(segment
		(start 170.24985 -334.76184)
		(end 170.965622 -335.477612)
		(width 0.381)
		(layer "In6.Cu")
		(net "GND")
	)
	(segment
		(start 298.633642 -373.15394)
		(end 299.33138 -372.456202)
		(width 0.508)
		(layer "In6.Cu")
		(net "GND")
	)
	(segment
		(start 85.147658 -216.512902)
		(end 85.147658 -216.382092)
		(width 0.254)
		(layer "In6.Cu")
		(net "GND")
	)
	(segment
		(start 55.11673 -185.30443)
		(end 28.4226 -185.30443)
		(width 0.254)
		(layer "In6.Cu")
		(net "GND")
	)
	(segment
		(start 170.965622 -335.477612)
		(end 171.681394 -334.76184)
		(width 0.381)
		(layer "In6.Cu")
		(net "GND")
	)
	(segment
		(start 193.641472 -21.358352)
		(end 193.701924 -21.358352)
		(width 0.254)
		(layer "In6.Cu")
		(net "GND")
	)
	(segment
		(start 91.247468 -219.995496)
		(end 91.237054 -220.001592)
		(width 0.0889)
		(layer "In6.Cu")
		(net "GND")
	)
	(segment
		(start 133.027674 -366.445546)
		(end 133.725412 -365.747808)
		(width 0.381)
		(layer "In6.Cu")
		(net "GND")
	)
	(segment
		(start 28.4226 -185.30443)
		(end 22.60727 -179.4891)
		(width 0.254)
		(layer "In6.Cu")
		(net "GND")
	)
	(segment
		(start 107.724702 -229.001828)
		(end 107.635548 -228.977952)
		(width 0.0889)
		(layer "In6.Cu")
		(net "GND")
	)
	(segment
		(start 85.227922 -217.07856)
		(end 85.227668 -217.078306)
		(width 0.0889)
		(layer "In6.Cu")
		(net "GND")
	)
	(segment
		(start 133.725412 -365.747808)
		(end 134.42315 -365.05007)
		(width 0.381)
		(layer "In6.Cu")
		(net "GND")
	)
	(segment
		(start 194.825112 -24.369522)
		(end 194.82943 -24.37384)
		(width 0.254)
		(layer "In6.Cu")
		(net "GND")
	)
	(segment
		(start 98.685096 -222.445834)
		(end 98.670364 -222.437198)
		(width 0.0889)
		(layer "In6.Cu")
		(net "GND")
	)
	(segment
		(start 94.066614 -219.995496)
		(end 94.0562 -220.001592)
		(width 0.0889)
		(layer "In6.Cu")
		(net "GND")
	)
	(segment
		(start 197.995032 -30.552136)
		(end 197.28942 -29.846524)
		(width 0.254)
		(layer "In6.Cu")
		(net "GND")
	)
	(segment
		(start 57.21985 -187.45581)
		(end 57.21985 -187.40755)
		(width 0.254)
		(layer "In6.Cu")
		(net "GND")
	)
	(segment
		(start 96.799654 -220.814646)
		(end 96.790764 -220.809566)
		(width 0.0889)
		(layer "In6.Cu")
		(net "GND")
	)
	(segment
		(start 92.187014 -219.995496)
		(end 92.1766 -220.001592)
		(width 0.0889)
		(layer "In6.Cu")
		(net "GND")
	)
	(segment
		(start 100.267262 -225.217482)
		(end 100.267262 -225.203258)
		(width 0.0889)
		(layer "In6.Cu")
		(net "GND")
	)
	(segment
		(start 427.490128 -344.017346)
		(end 428.2059 -344.733118)
		(width 0.381)
		(layer "In6.Cu")
		(net "GND")
	)
	(segment
		(start 189.4586 -17.459452)
		(end 189.26302 -17.655032)
		(width 0.254)
		(layer "In6.Cu")
		(net "GND")
	)
	(segment
		(start 198.153782 -30.552136)
		(end 197.995032 -30.552136)
		(width 0.254)
		(layer "In6.Cu")
		(net "GND")
	)
	(segment
		(start 196.581522 -29.131768)
		(end 197.28942 -29.839666)
		(width 0.254)
		(layer "In6.Cu")
		(net "GND")
	)
	(segment
		(start 182.638192 -336.199734)
		(end 183.353964 -335.483962)
		(width 0.381)
		(layer "In6.Cu")
		(net "GND")
	)
	(segment
		(start 381.053086 -364.942882)
		(end 381.750824 -365.64062)
		(width 0.381)
		(layer "In6.Cu")
		(net "GND")
	)
	(segment
		(start 85.147658 -216.55405)
		(end 85.147658 -216.512902)
		(width 0.0889)
		(layer "In6.Cu")
		(net "GND")
	)
	(segment
		(start 426.008038 -372.466108)
		(end 426.705776 -371.76837)
		(width 0.508)
		(layer "In6.Cu")
		(net "GND")
	)
	(segment
		(start 415.101786 -344.010996)
		(end 415.817558 -343.295224)
		(width 0.381)
		(layer "In6.Cu")
		(net "GND")
	)
	(segment
		(start 190.103252 -17.459452)
		(end 189.4586 -17.459452)
		(width 0.254)
		(layer "In6.Cu")
		(net "GND")
	)
	(segment
		(start 182.638192 -334.76819)
		(end 183.353964 -335.483962)
		(width 0.381)
		(layer "In6.Cu")
		(net "GND")
	)
	(segment
		(start 194.833494 -25.389586)
		(end 194.833494 -25.824688)
		(width 0.254)
		(layer "In6.Cu")
		(net "GND")
	)
	(segment
		(start 195.52285 -27.562556)
		(end 195.867274 -28.394152)
		(width 0.254)
		(layer "In6.Cu")
		(net "GND")
	)
	(segment
		(start 426.008038 -371.070632)
		(end 426.705776 -371.76837)
		(width 0.508)
		(layer "In6.Cu")
		(net "GND")
	)
	(segment
		(start 88.14562 -220.071188)
		(end 87.631778 -220.071188)
		(width 0.0889)
		(layer "In6.Cu")
		(net "GND")
	)
	(segment
		(start 181.836314 -362.415328)
		(end 182.534052 -363.113066)
		(width 0.508)
		(layer "In6.Cu")
		(net "GND")
	)
	(segment
		(start 170.24985 -336.193384)
		(end 170.965622 -335.477612)
		(width 0.381)
		(layer "In6.Cu")
		(net "GND")
	)
	(segment
		(start 103.384096 -228.957124)
		(end 103.369364 -228.948488)
		(width 0.0889)
		(layer "In6.Cu")
		(net "GND")
	)
	(segment
		(start 426.705776 -371.76837)
		(end 427.403514 -372.466108)
		(width 0.508)
		(layer "In6.Cu")
		(net "GND")
	)
	(segment
		(start 101.677216 -227.667058)
		(end 101.677216 -227.64496)
		(width 0.0889)
		(layer "In6.Cu")
		(net "GND")
	)
	(segment
		(start 170.965622 -335.477612)
		(end 171.681394 -336.193384)
		(width 0.381)
		(layer "In6.Cu")
		(net "GND")
	)
	(segment
		(start 196.581522 -29.116782)
		(end 196.581522 -29.131768)
		(width 0.254)
		(layer "In6.Cu")
		(net "GND")
	)
	(segment
		(start 100.558854 -225.69805)
		(end 100.549964 -225.69297)
		(width 0.0889)
		(layer "In6.Cu")
		(net "GND")
	)
	(segment
		(start 95.006668 -219.995496)
		(end 94.996254 -220.001592)
		(width 0.0889)
		(layer "In6.Cu")
		(net "GND")
	)
	(segment
		(start 195.52285 -27.426158)
		(end 195.52285 -27.562556)
		(width 0.254)
		(layer "In6.Cu")
		(net "GND")
	)
	(segment
		(start 193.701924 -21.358352)
		(end 194.527932 -22.18436)
		(width 0.254)
		(layer "In6.Cu")
		(net "GND")
	)
	(segment
		(start 78.7146 -209.94116)
		(end 72.544178 -195.044822)
		(width 0.254)
		(layer "In6.Cu")
		(net "GND")
	)
	(segment
		(start 22.60727 -179.4891)
		(end 22.60727 -177.37455)
		(width 0.254)
		(layer "In6.Cu")
		(net "GND")
	)
	(segment
		(start 194.825112 -23.23846)
		(end 194.825112 -24.369522)
		(width 0.254)
		(layer "In6.Cu")
		(net "GND")
	)
	(segment
		(start 133.725412 -365.747808)
		(end 134.42315 -366.445546)
		(width 0.381)
		(layer "In6.Cu")
		(net "GND")
	)
	(segment
		(start 177.156364 -335.483962)
		(end 177.872136 -336.199734)
		(width 0.381)
		(layer "In6.Cu")
		(net "GND")
	)
	(segment
		(start 105.263696 -228.957124)
		(end 105.248964 -228.948488)
		(width 0.0889)
		(layer "In6.Cu")
		(net "GND")
	)
	(segment
		(start 99.797616 -222.783654)
		(end 99.797616 -222.761556)
		(width 0.0889)
		(layer "In6.Cu")
		(net "GND")
	)
	(segment
		(start 415.101786 -344.010996)
		(end 415.817558 -344.726768)
		(width 0.381)
		(layer "In6.Cu")
		(net "GND")
	)
	(segment
		(start 85.147658 -216.382092)
		(end 84.403692 -215.638126)
		(width 0.254)
		(layer "In6.Cu")
		(net "GND")
	)
	(segment
		(start 93.127068 -219.995496)
		(end 93.116654 -220.001592)
		(width 0.0889)
		(layer "In6.Cu")
		(net "GND")
	)
	(segment
		(start 195.398136 -27.301444)
		(end 195.52285 -27.426158)
		(width 0.254)
		(layer "In6.Cu")
		(net "GND")
	)
	(segment
		(start 107.143296 -228.957124)
		(end 107.128564 -228.948488)
		(width 0.0889)
		(layer "In6.Cu")
		(net "GND")
	)
	(segment
		(start 104.323896 -228.957124)
		(end 104.309164 -228.948488)
		(width 0.0889)
		(layer "In6.Cu")
		(net "GND")
	)
	(segment
		(start 421.292528 -344.017346)
		(end 422.0083 -343.301574)
		(width 0.381)
		(layer "In6.Cu")
		(net "GND")
	)
	(segment
		(start 194.82943 -24.37384)
		(end 194.82943 -25.385522)
		(width 0.254)
		(layer "In6.Cu")
		(net "GND")
	)
	(segment
		(start 286.583628 -345.416124)
		(end 287.2994 -344.700352)
		(width 0.381)
		(layer "In6.Cu")
		(net "GND")
	)
	(segment
		(start 63.971424 -187.776104)
		(end 57.540144 -187.776104)
		(width 0.254)
		(layer "In6.Cu")
		(net "GND")
	)
	(arc
		(start 90.297 -220.001592)
		(mid 90.018822 -220.071315)
		(end 89.742264 -219.995496)
		(width 0.0889)
		(layer "In6.Cu")
		(net "GND")
	)
	(arc
		(start 94.996254 -220.001592)
		(mid 94.717822 -220.071438)
		(end 94.44101 -219.995496)
		(width 0.0889)
		(layer "In6.Cu")
		(net "GND")
	)
	(arc
		(start 99.797616 -222.761556)
		(mid 99.610317 -222.437115)
		(end 99.235768 -222.437198)
		(width 0.0889)
		(layer "In6.Cu")
		(net "GND")
	)
	(arc
		(start 96.508062 -220.319854)
		(mid 96.460383 -220.136954)
		(end 96.3295 -220.000576)
		(width 0.0889)
		(layer "In6.Cu")
		(net "GND")
	)
	(arc
		(start 96.978216 -221.133924)
		(mid 96.930537 -220.951024)
		(end 96.799654 -220.814646)
		(width 0.0889)
		(layer "In6.Cu")
		(net "GND")
	)
	(arc
		(start 88.428068 -219.995496)
		(mid 88.291822 -220.051905)
		(end 88.14562 -220.071188)
		(width 0.0889)
		(layer "In6.Cu")
		(net "GND")
	)
	(arc
		(start 96.32061 -219.995496)
		(mid 96.133412 -219.945353)
		(end 95.946214 -219.995496)
		(width 0.0889)
		(layer "In6.Cu")
		(net "GND")
	)
	(arc
		(start 94.44101 -219.995496)
		(mid 94.253812 -219.945353)
		(end 94.066614 -219.995496)
		(width 0.0889)
		(layer "In6.Cu")
		(net "GND")
	)
	(arc
		(start 102.994968 -228.948488)
		(mid 102.429691 -228.948562)
		(end 102.146862 -228.45903)
		(width 0.0889)
		(layer "In6.Cu")
		(net "GND")
	)
	(arc
		(start 100.737416 -226.017328)
		(mid 100.689737 -225.834428)
		(end 100.558854 -225.69805)
		(width 0.0889)
		(layer "In6.Cu")
		(net "GND")
	)
	(arc
		(start 104.309164 -228.948488)
		(mid 104.121966 -228.898345)
		(end 103.934768 -228.948488)
		(width 0.0889)
		(layer "In6.Cu")
		(net "GND")
	)
	(arc
		(start 105.248964 -228.948488)
		(mid 105.061766 -228.898345)
		(end 104.874568 -228.948488)
		(width 0.0889)
		(layer "In6.Cu")
		(net "GND")
	)
	(arc
		(start 99.235768 -222.437198)
		(mid 98.961569 -222.513033)
		(end 98.685096 -222.445834)
		(width 0.0889)
		(layer "In6.Cu")
		(net "GND")
	)
	(arc
		(start 95.381064 -219.995496)
		(mid 95.193866 -219.945353)
		(end 95.006668 -219.995496)
		(width 0.0889)
		(layer "In6.Cu")
		(net "GND")
	)
	(arc
		(start 98.670364 -222.437198)
		(mid 98.483166 -222.387055)
		(end 98.295968 -222.437198)
		(width 0.0889)
		(layer "In6.Cu")
		(net "GND")
	)
	(arc
		(start 104.874568 -228.948488)
		(mid 104.600369 -229.024323)
		(end 104.323896 -228.957124)
		(width 0.0889)
		(layer "In6.Cu")
		(net "GND")
	)
	(arc
		(start 99.797616 -224.373948)
		(mid 99.876986 -224.100214)
		(end 100.07981 -223.899984)
		(width 0.0889)
		(layer "In6.Cu")
		(net "GND")
	)
	(arc
		(start 97.447862 -221.94774)
		(mid 97.400183 -221.76484)
		(end 97.2693 -221.628462)
		(width 0.0889)
		(layer "In6.Cu")
		(net "GND")
	)
	(arc
		(start 96.790764 -220.809566)
		(mid 96.585692 -220.605887)
		(end 96.508062 -220.327474)
		(width 0.0889)
		(layer "In6.Cu")
		(net "GND")
	)
	(arc
		(start 98.295968 -222.437198)
		(mid 98.021769 -222.513033)
		(end 97.745296 -222.445834)
		(width 0.0889)
		(layer "In6.Cu")
		(net "GND")
	)
	(arc
		(start 103.934768 -228.948488)
		(mid 103.660569 -229.024323)
		(end 103.384096 -228.957124)
		(width 0.0889)
		(layer "In6.Cu")
		(net "GND")
	)
	(arc
		(start 93.116654 -220.001592)
		(mid 92.838222 -220.071438)
		(end 92.56141 -219.995496)
		(width 0.0889)
		(layer "In6.Cu")
		(net "GND")
	)
	(arc
		(start 106.754168 -228.948488)
		(mid 106.479969 -229.024323)
		(end 106.203496 -228.957124)
		(width 0.0889)
		(layer "In6.Cu")
		(net "GND")
	)
	(arc
		(start 105.814368 -228.948488)
		(mid 105.540169 -229.024323)
		(end 105.263696 -228.957124)
		(width 0.0889)
		(layer "In6.Cu")
		(net "GND")
	)
	(arc
		(start 102.146862 -228.45903)
		(mid 102.099183 -228.27613)
		(end 101.9683 -228.139752)
		(width 0.0889)
		(layer "In6.Cu")
		(net "GND")
	)
	(arc
		(start 100.07981 -224.8789)
		(mid 99.876987 -224.678669)
		(end 99.797616 -224.404936)
		(width 0.0889)
		(layer "In6.Cu")
		(net "GND")
	)
	(arc
		(start 94.0562 -220.001592)
		(mid 93.778022 -220.071315)
		(end 93.501464 -219.995496)
		(width 0.0889)
		(layer "In6.Cu")
		(net "GND")
	)
	(arc
		(start 97.695004 -222.416116)
		(mid 97.513945 -222.231796)
		(end 97.447862 -221.98203)
		(width 0.0889)
		(layer "In6.Cu")
		(net "GND")
	)
	(arc
		(start 91.621864 -219.995496)
		(mid 91.434666 -219.945353)
		(end 91.247468 -219.995496)
		(width 0.0889)
		(layer "In6.Cu")
		(net "GND")
	)
	(arc
		(start 101.019864 -226.506786)
		(mid 100.815529 -226.304181)
		(end 100.737416 -226.027234)
		(width 0.0889)
		(layer "In6.Cu")
		(net "GND")
	)
	(arc
		(start 91.237054 -220.001592)
		(mid 90.958622 -220.071438)
		(end 90.68181 -219.995496)
		(width 0.0889)
		(layer "In6.Cu")
		(net "GND")
	)
	(arc
		(start 88.802464 -219.995496)
		(mid 88.615266 -219.945353)
		(end 88.428068 -219.995496)
		(width 0.0889)
		(layer "In6.Cu")
		(net "GND")
	)
	(arc
		(start 101.677216 -227.64496)
		(mid 101.629537 -227.46206)
		(end 101.498654 -227.325682)
		(width 0.0889)
		(layer "In6.Cu")
		(net "GND")
	)
	(arc
		(start 101.95941 -228.134672)
		(mid 101.758128 -227.937185)
		(end 101.677216 -227.667058)
		(width 0.0889)
		(layer "In6.Cu")
		(net "GND")
	)
	(arc
		(start 107.128564 -228.948488)
		(mid 106.941366 -228.898345)
		(end 106.754168 -228.948488)
		(width 0.0889)
		(layer "In6.Cu")
		(net "GND")
	)
	(arc
		(start 103.369364 -228.948488)
		(mid 103.182166 -228.898345)
		(end 102.994968 -228.948488)
		(width 0.0889)
		(layer "In6.Cu")
		(net "GND")
	)
	(arc
		(start 101.483668 -227.317046)
		(mid 101.281081 -227.110695)
		(end 101.207062 -226.831144)
		(width 0.0889)
		(layer "In6.Cu")
		(net "GND")
	)
	(arc
		(start 100.07981 -223.251268)
		(mid 99.878528 -223.053781)
		(end 99.797616 -222.783654)
		(width 0.0889)
		(layer "In6.Cu")
		(net "GND")
	)
	(arc
		(start 101.207062 -226.822508)
		(mid 101.154792 -226.640143)
		(end 101.019864 -226.506786)
		(width 0.0889)
		(layer "In6.Cu")
		(net "GND")
	)
	(arc
		(start 85.700616 -217.878406)
		(mid 85.652937 -217.695506)
		(end 85.522054 -217.559128)
		(width 0.0889)
		(layer "In6.Cu")
		(net "GND")
	)
	(arc
		(start 90.68181 -219.995496)
		(mid 90.494612 -219.945353)
		(end 90.307414 -219.995496)
		(width 0.0889)
		(layer "In6.Cu")
		(net "GND")
	)
	(arc
		(start 95.9358 -220.001592)
		(mid 95.657622 -220.071315)
		(end 95.381064 -219.995496)
		(width 0.0889)
		(layer "In6.Cu")
		(net "GND")
	)
	(arc
		(start 85.511386 -217.553032)
		(mid 85.307392 -217.352991)
		(end 85.227922 -217.07856)
		(width 0.0889)
		(layer "In6.Cu")
		(net "GND")
	)
	(arc
		(start 106.188764 -228.948488)
		(mid 106.001566 -228.898345)
		(end 105.814368 -228.948488)
		(width 0.0889)
		(layer "In6.Cu")
		(net "GND")
	)
	(arc
		(start 100.549964 -225.69297)
		(mid 100.346483 -225.492166)
		(end 100.267262 -225.217482)
		(width 0.0889)
		(layer "In6.Cu")
		(net "GND")
	)
	(arc
		(start 100.0887 -223.894904)
		(mid 100.267297 -223.575626)
		(end 100.0887 -223.256348)
		(width 0.0889)
		(layer "In6.Cu")
		(net "GND")
	)
	(arc
		(start 107.635548 -228.977952)
		(mid 107.387043 -229.023939)
		(end 107.143296 -228.957124)
		(width 0.0889)
		(layer "In6.Cu")
		(net "GND")
	)
	(arc
		(start 92.1766 -220.001592)
		(mid 91.898422 -220.071315)
		(end 91.621864 -219.995496)
		(width 0.0889)
		(layer "In6.Cu")
		(net "GND")
	)
	(arc
		(start 92.56141 -219.995496)
		(mid 92.374212 -219.945353)
		(end 92.187014 -219.995496)
		(width 0.0889)
		(layer "In6.Cu")
		(net "GND")
	)
	(arc
		(start 93.501464 -219.995496)
		(mid 93.314266 -219.945353)
		(end 93.127068 -219.995496)
		(width 0.0889)
		(layer "In6.Cu")
		(net "GND")
	)
	(arc
		(start 87.631778 -220.071188)
		(mid 87.4971 -220.044493)
		(end 87.382858 -219.968318)
		(width 0.0889)
		(layer "In6.Cu")
		(net "GND")
	)
	(arc
		(start 100.267262 -225.203258)
		(mid 100.219583 -225.020358)
		(end 100.0887 -224.88398)
		(width 0.0889)
		(layer "In6.Cu")
		(net "GND")
	)
	(arc
		(start 89.367868 -219.995496)
		(mid 89.085166 -220.071272)
		(end 88.802464 -219.995496)
		(width 0.0889)
		(layer "In6.Cu")
		(net "GND")
	)
	(arc
		(start 89.742264 -219.995496)
		(mid 89.555066 -219.945353)
		(end 89.367868 -219.995496)
		(width 0.0889)
		(layer "In6.Cu")
		(net "GND")
	)
	(arc
		(start 97.26041 -221.623382)
		(mid 97.057587 -221.423151)
		(end 96.978216 -221.149418)
		(width 0.0889)
		(layer "In6.Cu")
		(net "GND")
	)
	(segment
		(start 429.089058 -175.777906)
		(end 426.971714 -177.89525)
		(width 0.254)
		(layer "In11.Cu")
		(net "GND")
	)
	(segment
		(start 402.62556 -184.742836)
		(end 389.289544 -198.078852)
		(width 0.254)
		(layer "In11.Cu")
		(net "GND")
	)
	(segment
		(start 350.557084 -222.746062)
		(end 350.557084 -222.761556)
		(width 0.0889)
		(layer "In11.Cu")
		(net "GND")
	)
	(segment
		(start 298.633642 -371.758464)
		(end 299.33138 -372.456202)
		(width 0.508)
		(layer "In11.Cu")
		(net "GND")
	)
	(segment
		(start 369.260882 -222.272098)
		(end 369.24615 -222.263462)
		(width 0.0889)
		(layer "In11.Cu")
		(net "GND")
	)
	(segment
		(start 381.478536 -222.272098)
		(end 381.468122 -222.266002)
		(width 0.0889)
		(layer "In11.Cu")
		(net "GND")
	)
	(segment
		(start 361.742736 -222.272098)
		(end 361.732322 -222.266002)
		(width 0.0889)
		(layer "In11.Cu")
		(net "GND")
	)
	(segment
		(start 350.08693 -223.568006)
		(end 350.08693 -223.575626)
		(width 0.0889)
		(layer "In11.Cu")
		(net "GND")
	)
	(segment
		(start 181.836314 -362.415328)
		(end 182.534052 -363.113066)
		(width 0.508)
		(layer "In11.Cu")
		(net "GND")
	)
	(segment
		(start 426.971714 -177.89525)
		(end 426.971714 -180.176424)
		(width 0.254)
		(layer "In11.Cu")
		(net "GND")
	)
	(segment
		(start 385.799584 -217.05443)
		(end 385.799584 -217.064336)
		(width 0.0889)
		(layer "In11.Cu")
		(net "GND")
	)
	(segment
		(start 349.429832 -227.320602)
		(end 349.438722 -227.325682)
		(width 0.0889)
		(layer "In11.Cu")
		(net "GND")
	)
	(segment
		(start 182.534052 -363.113066)
		(end 183.23179 -362.415328)
		(width 0.508)
		(layer "In11.Cu")
		(net "GND")
	)
	(segment
		(start 435.446932 -175.00092)
		(end 434.8988 -174.452788)
		(width 0.254)
		(layer "In11.Cu")
		(net "GND")
	)
	(segment
		(start 367.381536 -222.272098)
		(end 367.371122 -222.266002)
		(width 0.0889)
		(layer "In11.Cu")
		(net "GND")
	)
	(segment
		(start 133.027674 -365.05007)
		(end 133.725412 -365.747808)
		(width 0.381)
		(layer "In11.Cu")
		(net "GND")
	)
	(segment
		(start 366.441482 -222.272098)
		(end 366.42675 -222.263462)
		(width 0.0889)
		(layer "In11.Cu")
		(net "GND")
	)
	(segment
		(start 299.33138 -372.456202)
		(end 300.029118 -371.758464)
		(width 0.508)
		(layer "In11.Cu")
		(net "GND")
	)
	(segment
		(start 386.916422 -215.504268)
		(end 386.642356 -215.778334)
		(width 0.254)
		(layer "In11.Cu")
		(net "GND")
	)
	(segment
		(start 349.438722 -224.70872)
		(end 349.429832 -224.7138)
		(width 0.0889)
		(layer "In11.Cu")
		(net "GND")
	)
	(segment
		(start 389.289544 -212.581236)
		(end 386.916422 -214.954358)
		(width 0.254)
		(layer "In11.Cu")
		(net "GND")
	)
	(segment
		(start 370.200682 -222.272098)
		(end 370.18595 -222.263462)
		(width 0.0889)
		(layer "In11.Cu")
		(net "GND")
	)
	(segment
		(start 348.677484 -225.99523)
		(end 348.677484 -226.027234)
		(width 0.0889)
		(layer "In11.Cu")
		(net "GND")
	)
	(segment
		(start 436.1561 -175.00092)
		(end 435.446932 -175.00092)
		(width 0.254)
		(layer "In11.Cu")
		(net "GND")
	)
	(segment
		(start 382.980184 -221.937834)
		(end 382.980184 -221.94774)
		(width 0.0889)
		(layer "In11.Cu")
		(net "GND")
	)
	(segment
		(start 376.779282 -222.272098)
		(end 376.76455 -222.263462)
		(width 0.0889)
		(layer "In11.Cu")
		(net "GND")
	)
	(segment
		(start 349.423736 -227.317046)
		(end 349.429832 -227.320602)
		(width 0.0889)
		(layer "In11.Cu")
		(net "GND")
	)
	(segment
		(start 170.24985 -336.193384)
		(end 170.965622 -335.477612)
		(width 0.381)
		(layer "In11.Cu")
		(net "GND")
	)
	(segment
		(start 384.859784 -218.682316)
		(end 384.859784 -218.692222)
		(width 0.0889)
		(layer "In11.Cu")
		(net "GND")
	)
	(segment
		(start 350.378522 -223.080834)
		(end 350.369632 -223.085914)
		(width 0.0889)
		(layer "In11.Cu")
		(net "GND")
	)
	(segment
		(start 352.344482 -222.272098)
		(end 352.32975 -222.263462)
		(width 0.0889)
		(layer "In11.Cu")
		(net "GND")
	)
	(segment
		(start 133.725412 -365.747808)
		(end 134.42315 -366.445546)
		(width 0.381)
		(layer "In11.Cu")
		(net "GND")
	)
	(segment
		(start 351.905824 -229.002082)
		(end 352.062034 -229.272846)
		(width 0.0889)
		(layer "In11.Cu")
		(net "GND")
	)
	(segment
		(start 349.617284 -227.64496)
		(end 349.617284 -227.667058)
		(width 0.0889)
		(layer "In11.Cu")
		(net "GND")
	)
	(segment
		(start 299.33138 -372.456202)
		(end 300.029118 -373.15394)
		(width 0.508)
		(layer "In11.Cu")
		(net "GND")
	)
	(segment
		(start 379.598682 -222.272098)
		(end 379.58395 -222.263462)
		(width 0.0889)
		(layer "In11.Cu")
		(net "GND")
	)
	(segment
		(start 431.733452 -174.452788)
		(end 430.408334 -175.777906)
		(width 0.254)
		(layer "In11.Cu")
		(net "GND")
	)
	(segment
		(start 170.965622 -335.477612)
		(end 171.681394 -334.76184)
		(width 0.381)
		(layer "In11.Cu")
		(net "GND")
	)
	(segment
		(start 364.561882 -222.272098)
		(end 364.54715 -222.263462)
		(width 0.0889)
		(layer "In11.Cu")
		(net "GND")
	)
	(segment
		(start 426.705776 -371.76837)
		(end 427.403514 -371.070632)
		(width 0.508)
		(layer "In11.Cu")
		(net "GND")
	)
	(segment
		(start 354.224082 -222.272098)
		(end 354.20935 -222.263462)
		(width 0.0889)
		(layer "In11.Cu")
		(net "GND")
	)
	(segment
		(start 360.802682 -222.272098)
		(end 360.78795 -222.263462)
		(width 0.0889)
		(layer "In11.Cu")
		(net "GND")
	)
	(segment
		(start 355.163882 -222.272098)
		(end 355.14915 -222.263462)
		(width 0.0889)
		(layer "In11.Cu")
		(net "GND")
	)
	(segment
		(start 133.027674 -366.445546)
		(end 133.725412 -365.747808)
		(width 0.381)
		(layer "In11.Cu")
		(net "GND")
	)
	(segment
		(start 349.617284 -224.373948)
		(end 349.617284 -224.389442)
		(width 0.0889)
		(layer "In11.Cu")
		(net "GND")
	)
	(segment
		(start 384.672332 -219.01658)
		(end 384.666236 -219.020136)
		(width 0.0889)
		(layer "In11.Cu")
		(net "GND")
	)
	(segment
		(start 374.899682 -222.272098)
		(end 374.88495 -222.263462)
		(width 0.0889)
		(layer "In11.Cu")
		(net "GND")
	)
	(segment
		(start 365.501682 -222.272098)
		(end 365.48695 -222.263462)
		(width 0.0889)
		(layer "In11.Cu")
		(net "GND")
	)
	(segment
		(start 351.81667 -228.978206)
		(end 351.905824 -229.002082)
		(width 0.0889)
		(layer "In11.Cu")
		(net "GND")
	)
	(segment
		(start 357.043482 -222.272098)
		(end 357.02875 -222.263462)
		(width 0.0889)
		(layer "In11.Cu")
		(net "GND")
	)
	(segment
		(start 363.622082 -222.272098)
		(end 363.611668 -222.266002)
		(width 0.0889)
		(layer "In11.Cu")
		(net "GND")
	)
	(segment
		(start 348.968568 -225.522536)
		(end 348.959678 -225.527616)
		(width 0.0889)
		(layer "In11.Cu")
		(net "GND")
	)
	(segment
		(start 383.741422 -220.639132)
		(end 383.732532 -220.644212)
		(width 0.0889)
		(layer "In11.Cu")
		(net "GND")
	)
	(segment
		(start 373.959882 -222.272098)
		(end 373.94515 -222.263462)
		(width 0.0889)
		(layer "In11.Cu")
		(net "GND")
	)
	(segment
		(start 133.725412 -365.747808)
		(end 134.42315 -365.05007)
		(width 0.381)
		(layer "In11.Cu")
		(net "GND")
	)
	(segment
		(start 176.440592 -334.76819)
		(end 177.156364 -335.483962)
		(width 0.381)
		(layer "In11.Cu")
		(net "GND")
	)
	(segment
		(start 183.353964 -335.483962)
		(end 184.069736 -334.76819)
		(width 0.381)
		(layer "In11.Cu")
		(net "GND")
	)
	(segment
		(start 357.983536 -222.272098)
		(end 357.973122 -222.266002)
		(width 0.0889)
		(layer "In11.Cu")
		(net "GND")
	)
	(segment
		(start 176.440592 -336.199734)
		(end 177.156364 -335.483962)
		(width 0.381)
		(layer "In11.Cu")
		(net "GND")
	)
	(segment
		(start 372.080282 -222.272098)
		(end 372.06555 -222.263462)
		(width 0.0889)
		(layer "In11.Cu")
		(net "GND")
	)
	(segment
		(start 350.369632 -228.948488)
		(end 350.384364 -228.957124)
		(width 0.0889)
		(layer "In11.Cu")
		(net "GND")
	)
	(segment
		(start 182.638192 -334.76819)
		(end 183.353964 -335.483962)
		(width 0.381)
		(layer "In11.Cu")
		(net "GND")
	)
	(segment
		(start 386.642356 -216.032842)
		(end 386.159756 -216.515442)
		(width 0.0889)
		(layer "In11.Cu")
		(net "GND")
	)
	(segment
		(start 371.140482 -222.272098)
		(end 371.12575 -222.263462)
		(width 0.0889)
		(layer "In11.Cu")
		(net "GND")
	)
	(segment
		(start 434.4797 -175.597058)
		(end 435.057042 -176.1744)
		(width 0.254)
		(layer "In11.Cu")
		(net "GND")
	)
	(segment
		(start 368.321082 -222.272098)
		(end 368.310668 -222.266002)
		(width 0.0889)
		(layer "In11.Cu")
		(net "GND")
	)
	(segment
		(start 183.353964 -335.483962)
		(end 184.069736 -336.199734)
		(width 0.381)
		(layer "In11.Cu")
		(net "GND")
	)
	(segment
		(start 436.52694 -175.37176)
		(end 436.1561 -175.00092)
		(width 0.254)
		(layer "In11.Cu")
		(net "GND")
	)
	(segment
		(start 430.408334 -175.777906)
		(end 429.089058 -175.777906)
		(width 0.254)
		(layer "In11.Cu")
		(net "GND")
	)
	(segment
		(start 377.719082 -222.272098)
		(end 377.70435 -222.263462)
		(width 0.0889)
		(layer "In11.Cu")
		(net "GND")
	)
	(segment
		(start 426.008038 -371.070632)
		(end 426.705776 -371.76837)
		(width 0.508)
		(layer "In11.Cu")
		(net "GND")
	)
	(segment
		(start 385.151122 -218.197684)
		(end 385.142232 -218.202764)
		(width 0.0889)
		(layer "In11.Cu")
		(net "GND")
	)
	(segment
		(start 177.156364 -335.483962)
		(end 177.872136 -336.199734)
		(width 0.381)
		(layer "In11.Cu")
		(net "GND")
	)
	(segment
		(start 350.363536 -228.944932)
		(end 350.369632 -228.948488)
		(width 0.0889)
		(layer "In11.Cu")
		(net "GND")
	)
	(segment
		(start 182.638192 -336.199734)
		(end 183.353964 -335.483962)
		(width 0.381)
		(layer "In11.Cu")
		(net "GND")
	)
	(segment
		(start 359.862882 -222.272098)
		(end 359.852468 -222.266002)
		(width 0.0889)
		(layer "In11.Cu")
		(net "GND")
	)
	(segment
		(start 386.642356 -215.778334)
		(end 386.642356 -216.032842)
		(width 0.0889)
		(layer "In11.Cu")
		(net "GND")
	)
	(segment
		(start 356.103682 -222.272098)
		(end 356.08895 -222.263462)
		(width 0.0889)
		(layer "In11.Cu")
		(net "GND")
	)
	(segment
		(start 382.801622 -222.267018)
		(end 382.792732 -222.272098)
		(width 0.0889)
		(layer "In11.Cu")
		(net "GND")
	)
	(segment
		(start 383.271522 -221.453202)
		(end 383.262632 -221.458282)
		(width 0.0889)
		(layer "In11.Cu")
		(net "GND")
	)
	(segment
		(start 384.38963 -219.506038)
		(end 384.38963 -219.514674)
		(width 0.0889)
		(layer "In11.Cu")
		(net "GND")
	)
	(segment
		(start 351.29851 -228.942392)
		(end 351.309432 -228.948742)
		(width 0.0889)
		(layer "In11.Cu")
		(net "GND")
	)
	(segment
		(start 384.681222 -219.0115)
		(end 384.672332 -219.01658)
		(width 0.0889)
		(layer "In11.Cu")
		(net "GND")
	)
	(segment
		(start 389.289544 -198.078852)
		(end 389.289544 -212.581236)
		(width 0.254)
		(layer "In11.Cu")
		(net "GND")
	)
	(segment
		(start 386.916422 -214.954358)
		(end 386.916422 -215.504268)
		(width 0.254)
		(layer "In11.Cu")
		(net "GND")
	)
	(segment
		(start 380.538482 -222.272098)
		(end 380.52375 -222.263462)
		(width 0.0889)
		(layer "In11.Cu")
		(net "GND")
	)
	(segment
		(start 349.908368 -223.894904)
		(end 349.899478 -223.899984)
		(width 0.0889)
		(layer "In11.Cu")
		(net "GND")
	)
	(segment
		(start 422.405302 -184.742836)
		(end 402.62556 -184.742836)
		(width 0.254)
		(layer "In11.Cu")
		(net "GND")
	)
	(segment
		(start 426.971714 -180.176424)
		(end 422.405302 -184.742836)
		(width 0.254)
		(layer "In11.Cu")
		(net "GND")
	)
	(segment
		(start 436.18658 -176.1744)
		(end 436.52694 -175.83404)
		(width 0.254)
		(layer "In11.Cu")
		(net "GND")
	)
	(segment
		(start 170.24985 -334.76184)
		(end 170.965622 -335.477612)
		(width 0.381)
		(layer "In11.Cu")
		(net "GND")
	)
	(segment
		(start 373.020082 -222.272098)
		(end 373.00535 -222.263462)
		(width 0.0889)
		(layer "In11.Cu")
		(net "GND")
	)
	(segment
		(start 434.8988 -174.452788)
		(end 431.733452 -174.452788)
		(width 0.254)
		(layer "In11.Cu")
		(net "GND")
	)
	(segment
		(start 181.836314 -363.810804)
		(end 182.534052 -363.113066)
		(width 0.508)
		(layer "In11.Cu")
		(net "GND")
	)
	(segment
		(start 375.839482 -222.272098)
		(end 375.82475 -222.263462)
		(width 0.0889)
		(layer "In11.Cu")
		(net "GND")
	)
	(segment
		(start 349.429832 -224.7138)
		(end 349.423736 -224.717356)
		(width 0.0889)
		(layer "In11.Cu")
		(net "GND")
	)
	(segment
		(start 170.965622 -335.477612)
		(end 171.681394 -336.193384)
		(width 0.381)
		(layer "In11.Cu")
		(net "GND")
	)
	(segment
		(start 298.633642 -373.15394)
		(end 299.33138 -372.456202)
		(width 0.508)
		(layer "In11.Cu")
		(net "GND")
	)
	(segment
		(start 378.658882 -222.272098)
		(end 378.64415 -222.263462)
		(width 0.0889)
		(layer "In11.Cu")
		(net "GND")
	)
	(segment
		(start 177.156364 -335.483962)
		(end 177.872136 -334.76819)
		(width 0.381)
		(layer "In11.Cu")
		(net "GND")
	)
	(segment
		(start 435.057042 -176.1744)
		(end 436.18658 -176.1744)
		(width 0.254)
		(layer "In11.Cu")
		(net "GND")
	)
	(segment
		(start 385.621022 -217.383614)
		(end 385.612132 -217.388694)
		(width 0.0889)
		(layer "In11.Cu")
		(net "GND")
	)
	(segment
		(start 351.404682 -222.272098)
		(end 351.38995 -222.263462)
		(width 0.0889)
		(layer "In11.Cu")
		(net "GND")
	)
	(segment
		(start 426.008038 -372.466108)
		(end 426.705776 -371.76837)
		(width 0.508)
		(layer "In11.Cu")
		(net "GND")
	)
	(segment
		(start 349.899478 -228.134672)
		(end 349.908368 -228.139752)
		(width 0.0889)
		(layer "In11.Cu")
		(net "GND")
	)
	(segment
		(start 182.534052 -363.113066)
		(end 183.23179 -363.810804)
		(width 0.508)
		(layer "In11.Cu")
		(net "GND")
	)
	(segment
		(start 349.14713 -226.822508)
		(end 349.14713 -226.831144)
		(width 0.0889)
		(layer "In11.Cu")
		(net "GND")
	)
	(segment
		(start 353.284282 -222.272098)
		(end 353.26955 -222.263462)
		(width 0.0889)
		(layer "In11.Cu")
		(net "GND")
	)
	(segment
		(start 383.919984 -220.309948)
		(end 383.919984 -220.319854)
		(width 0.0889)
		(layer "In11.Cu")
		(net "GND")
	)
	(segment
		(start 383.450084 -221.115382)
		(end 383.450084 -221.133924)
		(width 0.0889)
		(layer "In11.Cu")
		(net "GND")
	)
	(segment
		(start 436.52694 -175.83404)
		(end 436.52694 -175.37176)
		(width 0.254)
		(layer "In11.Cu")
		(net "GND")
	)
	(segment
		(start 385.329684 -217.859864)
		(end 385.329684 -217.878406)
		(width 0.0889)
		(layer "In11.Cu")
		(net "GND")
	)
	(arc
		(start 356.08895 -222.263462)
		(mid 355.812475 -222.196142)
		(end 355.538278 -222.272098)
		(width 0.0889)
		(layer "In11.Cu")
		(net "GND")
	)
	(arc
		(start 349.617284 -224.389442)
		(mid 349.569605 -224.572342)
		(end 349.438722 -224.70872)
		(width 0.0889)
		(layer "In11.Cu")
		(net "GND")
	)
	(arc
		(start 382.792732 -222.272098)
		(mid 382.605534 -222.322241)
		(end 382.418336 -222.272098)
		(width 0.0889)
		(layer "In11.Cu")
		(net "GND")
	)
	(arc
		(start 384.666236 -219.020136)
		(mid 384.463649 -219.226487)
		(end 384.38963 -219.506038)
		(width 0.0889)
		(layer "In11.Cu")
		(net "GND")
	)
	(arc
		(start 350.557084 -222.761556)
		(mid 350.509405 -222.944456)
		(end 350.378522 -223.080834)
		(width 0.0889)
		(layer "In11.Cu")
		(net "GND")
	)
	(arc
		(start 350.08693 -223.575626)
		(mid 350.039251 -223.758526)
		(end 349.908368 -223.894904)
		(width 0.0889)
		(layer "In11.Cu")
		(net "GND")
	)
	(arc
		(start 375.82475 -222.263462)
		(mid 375.548275 -222.196142)
		(end 375.274078 -222.272098)
		(width 0.0889)
		(layer "In11.Cu")
		(net "GND")
	)
	(arc
		(start 386.159756 -216.515442)
		(mid 386.122846 -216.547713)
		(end 386.082032 -216.574878)
		(width 0.0889)
		(layer "In11.Cu")
		(net "GND")
	)
	(arc
		(start 349.14713 -226.831144)
		(mid 349.221121 -227.11071)
		(end 349.423736 -227.317046)
		(width 0.0889)
		(layer "In11.Cu")
		(net "GND")
	)
	(arc
		(start 354.598478 -222.272098)
		(mid 354.41128 -222.322241)
		(end 354.224082 -222.272098)
		(width 0.0889)
		(layer "In11.Cu")
		(net "GND")
	)
	(arc
		(start 361.732322 -222.266002)
		(mid 361.45389 -222.196156)
		(end 361.177078 -222.272098)
		(width 0.0889)
		(layer "In11.Cu")
		(net "GND")
	)
	(arc
		(start 358.923336 -222.272098)
		(mid 358.640634 -222.196322)
		(end 358.357932 -222.272098)
		(width 0.0889)
		(layer "In11.Cu")
		(net "GND")
	)
	(arc
		(start 360.78795 -222.263462)
		(mid 360.511475 -222.196142)
		(end 360.237278 -222.272098)
		(width 0.0889)
		(layer "In11.Cu")
		(net "GND")
	)
	(arc
		(start 364.936278 -222.272098)
		(mid 364.74908 -222.322241)
		(end 364.561882 -222.272098)
		(width 0.0889)
		(layer "In11.Cu")
		(net "GND")
	)
	(arc
		(start 351.38995 -222.263462)
		(mid 351.113475 -222.196142)
		(end 350.839278 -222.272098)
		(width 0.0889)
		(layer "In11.Cu")
		(net "GND")
	)
	(arc
		(start 348.677484 -226.027234)
		(mid 348.755595 -226.304183)
		(end 348.959932 -226.506786)
		(width 0.0889)
		(layer "In11.Cu")
		(net "GND")
	)
	(arc
		(start 383.262632 -221.458282)
		(mid 383.058297 -221.660887)
		(end 382.980184 -221.937834)
		(width 0.0889)
		(layer "In11.Cu")
		(net "GND")
	)
	(arc
		(start 357.417878 -222.272098)
		(mid 357.23068 -222.322241)
		(end 357.043482 -222.272098)
		(width 0.0889)
		(layer "In11.Cu")
		(net "GND")
	)
	(arc
		(start 372.454678 -222.272098)
		(mid 372.26748 -222.322241)
		(end 372.080282 -222.272098)
		(width 0.0889)
		(layer "In11.Cu")
		(net "GND")
	)
	(arc
		(start 365.876078 -222.272098)
		(mid 365.68888 -222.322241)
		(end 365.501682 -222.272098)
		(width 0.0889)
		(layer "In11.Cu")
		(net "GND")
	)
	(arc
		(start 385.142232 -218.202764)
		(mid 384.937897 -218.405369)
		(end 384.859784 -218.682316)
		(width 0.0889)
		(layer "In11.Cu")
		(net "GND")
	)
	(arc
		(start 368.695478 -222.272098)
		(mid 368.50828 -222.322241)
		(end 368.321082 -222.272098)
		(width 0.0889)
		(layer "In11.Cu")
		(net "GND")
	)
	(arc
		(start 373.94515 -222.263462)
		(mid 373.668675 -222.196142)
		(end 373.394478 -222.272098)
		(width 0.0889)
		(layer "In11.Cu")
		(net "GND")
	)
	(arc
		(start 351.779078 -222.272098)
		(mid 351.59188 -222.322241)
		(end 351.404682 -222.272098)
		(width 0.0889)
		(layer "In11.Cu")
		(net "GND")
	)
	(arc
		(start 379.033278 -222.272098)
		(mid 378.84608 -222.322241)
		(end 378.658882 -222.272098)
		(width 0.0889)
		(layer "In11.Cu")
		(net "GND")
	)
	(arc
		(start 352.32975 -222.263462)
		(mid 352.053275 -222.196142)
		(end 351.779078 -222.272098)
		(width 0.0889)
		(layer "In11.Cu")
		(net "GND")
	)
	(arc
		(start 384.859784 -218.692222)
		(mid 384.812105 -218.875122)
		(end 384.681222 -219.0115)
		(width 0.0889)
		(layer "In11.Cu")
		(net "GND")
	)
	(arc
		(start 382.418336 -222.272098)
		(mid 382.135634 -222.196322)
		(end 381.852932 -222.272098)
		(width 0.0889)
		(layer "In11.Cu")
		(net "GND")
	)
	(arc
		(start 359.297732 -222.272098)
		(mid 359.110534 -222.322241)
		(end 358.923336 -222.272098)
		(width 0.0889)
		(layer "In11.Cu")
		(net "GND")
	)
	(arc
		(start 350.839278 -222.272098)
		(mid 350.636455 -222.472329)
		(end 350.557084 -222.746062)
		(width 0.0889)
		(layer "In11.Cu")
		(net "GND")
	)
	(arc
		(start 370.18595 -222.263462)
		(mid 369.909475 -222.196142)
		(end 369.635278 -222.272098)
		(width 0.0889)
		(layer "In11.Cu")
		(net "GND")
	)
	(arc
		(start 359.852468 -222.266002)
		(mid 359.57429 -222.196279)
		(end 359.297732 -222.272098)
		(width 0.0889)
		(layer "In11.Cu")
		(net "GND")
	)
	(arc
		(start 382.980184 -221.94774)
		(mid 382.932505 -222.13064)
		(end 382.801622 -222.267018)
		(width 0.0889)
		(layer "In11.Cu")
		(net "GND")
	)
	(arc
		(start 350.369632 -223.085914)
		(mid 350.16456 -223.289593)
		(end 350.08693 -223.568006)
		(width 0.0889)
		(layer "In11.Cu")
		(net "GND")
	)
	(arc
		(start 376.213878 -222.272098)
		(mid 376.02668 -222.322241)
		(end 375.839482 -222.272098)
		(width 0.0889)
		(layer "In11.Cu")
		(net "GND")
	)
	(arc
		(start 368.310668 -222.266002)
		(mid 368.03249 -222.196279)
		(end 367.755932 -222.272098)
		(width 0.0889)
		(layer "In11.Cu")
		(net "GND")
	)
	(arc
		(start 348.959678 -225.527616)
		(mid 348.758396 -225.725103)
		(end 348.677484 -225.99523)
		(width 0.0889)
		(layer "In11.Cu")
		(net "GND")
	)
	(arc
		(start 361.177078 -222.272098)
		(mid 360.98988 -222.322241)
		(end 360.802682 -222.272098)
		(width 0.0889)
		(layer "In11.Cu")
		(net "GND")
	)
	(arc
		(start 381.468122 -222.266002)
		(mid 381.18969 -222.196156)
		(end 380.912878 -222.272098)
		(width 0.0889)
		(layer "In11.Cu")
		(net "GND")
	)
	(arc
		(start 377.153678 -222.272098)
		(mid 376.96648 -222.322241)
		(end 376.779282 -222.272098)
		(width 0.0889)
		(layer "In11.Cu")
		(net "GND")
	)
	(arc
		(start 363.611668 -222.266002)
		(mid 363.33349 -222.196279)
		(end 363.056932 -222.272098)
		(width 0.0889)
		(layer "In11.Cu")
		(net "GND")
	)
	(arc
		(start 381.852932 -222.272098)
		(mid 381.665734 -222.322241)
		(end 381.478536 -222.272098)
		(width 0.0889)
		(layer "In11.Cu")
		(net "GND")
	)
	(arc
		(start 353.658678 -222.272098)
		(mid 353.47148 -222.322241)
		(end 353.284282 -222.272098)
		(width 0.0889)
		(layer "In11.Cu")
		(net "GND")
	)
	(arc
		(start 373.00535 -222.263462)
		(mid 372.728875 -222.196142)
		(end 372.454678 -222.272098)
		(width 0.0889)
		(layer "In11.Cu")
		(net "GND")
	)
	(arc
		(start 369.24615 -222.263462)
		(mid 368.969675 -222.196142)
		(end 368.695478 -222.272098)
		(width 0.0889)
		(layer "In11.Cu")
		(net "GND")
	)
	(arc
		(start 380.912878 -222.272098)
		(mid 380.72568 -222.322241)
		(end 380.538482 -222.272098)
		(width 0.0889)
		(layer "In11.Cu")
		(net "GND")
	)
	(arc
		(start 371.514878 -222.272098)
		(mid 371.32768 -222.322241)
		(end 371.140482 -222.272098)
		(width 0.0889)
		(layer "In11.Cu")
		(net "GND")
	)
	(arc
		(start 363.056932 -222.272098)
		(mid 362.869734 -222.322241)
		(end 362.682536 -222.272098)
		(width 0.0889)
		(layer "In11.Cu")
		(net "GND")
	)
	(arc
		(start 349.899478 -223.899984)
		(mid 349.696655 -224.100215)
		(end 349.617284 -224.373948)
		(width 0.0889)
		(layer "In11.Cu")
		(net "GND")
	)
	(arc
		(start 349.423736 -224.717356)
		(mid 349.221149 -224.923707)
		(end 349.14713 -225.203258)
		(width 0.0889)
		(layer "In11.Cu")
		(net "GND")
	)
	(arc
		(start 356.478078 -222.272098)
		(mid 356.29088 -222.322241)
		(end 356.103682 -222.272098)
		(width 0.0889)
		(layer "In11.Cu")
		(net "GND")
	)
	(arc
		(start 379.973078 -222.272098)
		(mid 379.78588 -222.322241)
		(end 379.598682 -222.272098)
		(width 0.0889)
		(layer "In11.Cu")
		(net "GND")
	)
	(arc
		(start 348.959932 -226.506786)
		(mid 349.094865 -226.64014)
		(end 349.14713 -226.822508)
		(width 0.0889)
		(layer "In11.Cu")
		(net "GND")
	)
	(arc
		(start 370.575078 -222.272098)
		(mid 370.38788 -222.322241)
		(end 370.200682 -222.272098)
		(width 0.0889)
		(layer "In11.Cu")
		(net "GND")
	)
	(arc
		(start 385.799584 -217.064336)
		(mid 385.751905 -217.247236)
		(end 385.621022 -217.383614)
		(width 0.0889)
		(layer "In11.Cu")
		(net "GND")
	)
	(arc
		(start 367.755932 -222.272098)
		(mid 367.568734 -222.322241)
		(end 367.381536 -222.272098)
		(width 0.0889)
		(layer "In11.Cu")
		(net "GND")
	)
	(arc
		(start 377.70435 -222.263462)
		(mid 377.427875 -222.196142)
		(end 377.153678 -222.272098)
		(width 0.0889)
		(layer "In11.Cu")
		(net "GND")
	)
	(arc
		(start 360.237278 -222.272098)
		(mid 360.05008 -222.322241)
		(end 359.862882 -222.272098)
		(width 0.0889)
		(layer "In11.Cu")
		(net "GND")
	)
	(arc
		(start 384.202432 -219.830396)
		(mid 383.998097 -220.033001)
		(end 383.919984 -220.309948)
		(width 0.0889)
		(layer "In11.Cu")
		(net "GND")
	)
	(arc
		(start 385.612132 -217.388694)
		(mid 385.409846 -217.587675)
		(end 385.329684 -217.859864)
		(width 0.0889)
		(layer "In11.Cu")
		(net "GND")
	)
	(arc
		(start 371.12575 -222.263462)
		(mid 370.849275 -222.196142)
		(end 370.575078 -222.272098)
		(width 0.0889)
		(layer "In11.Cu")
		(net "GND")
	)
	(arc
		(start 351.309432 -228.948742)
		(mid 351.559558 -229.023691)
		(end 351.81667 -228.978206)
		(width 0.0889)
		(layer "In11.Cu")
		(net "GND")
	)
	(arc
		(start 375.274078 -222.272098)
		(mid 375.08688 -222.322241)
		(end 374.899682 -222.272098)
		(width 0.0889)
		(layer "In11.Cu")
		(net "GND")
	)
	(arc
		(start 384.38963 -219.514674)
		(mid 384.33736 -219.697039)
		(end 384.202432 -219.830396)
		(width 0.0889)
		(layer "In11.Cu")
		(net "GND")
	)
	(arc
		(start 350.08693 -228.45903)
		(mid 350.160921 -228.738596)
		(end 350.363536 -228.944932)
		(width 0.0889)
		(layer "In11.Cu")
		(net "GND")
	)
	(arc
		(start 378.093478 -222.272098)
		(mid 377.90628 -222.322241)
		(end 377.719082 -222.272098)
		(width 0.0889)
		(layer "In11.Cu")
		(net "GND")
	)
	(arc
		(start 357.02875 -222.263462)
		(mid 356.752275 -222.196142)
		(end 356.478078 -222.272098)
		(width 0.0889)
		(layer "In11.Cu")
		(net "GND")
	)
	(arc
		(start 367.371122 -222.266002)
		(mid 367.09269 -222.196156)
		(end 366.815878 -222.272098)
		(width 0.0889)
		(layer "In11.Cu")
		(net "GND")
	)
	(arc
		(start 350.384364 -228.957124)
		(mid 350.660839 -229.024444)
		(end 350.935036 -228.948488)
		(width 0.0889)
		(layer "In11.Cu")
		(net "GND")
	)
	(arc
		(start 352.718878 -222.272098)
		(mid 352.53168 -222.322241)
		(end 352.344482 -222.272098)
		(width 0.0889)
		(layer "In11.Cu")
		(net "GND")
	)
	(arc
		(start 386.082032 -216.574878)
		(mid 385.877697 -216.777483)
		(end 385.799584 -217.05443)
		(width 0.0889)
		(layer "In11.Cu")
		(net "GND")
	)
	(arc
		(start 349.14713 -225.203258)
		(mid 349.099451 -225.386158)
		(end 348.968568 -225.522536)
		(width 0.0889)
		(layer "In11.Cu")
		(net "GND")
	)
	(arc
		(start 366.815878 -222.272098)
		(mid 366.62868 -222.322241)
		(end 366.441482 -222.272098)
		(width 0.0889)
		(layer "In11.Cu")
		(net "GND")
	)
	(arc
		(start 358.357932 -222.272098)
		(mid 358.170734 -222.322241)
		(end 357.983536 -222.272098)
		(width 0.0889)
		(layer "In11.Cu")
		(net "GND")
	)
	(arc
		(start 376.76455 -222.263462)
		(mid 376.488075 -222.196142)
		(end 376.213878 -222.272098)
		(width 0.0889)
		(layer "In11.Cu")
		(net "GND")
	)
	(arc
		(start 362.117132 -222.272098)
		(mid 361.929934 -222.322241)
		(end 361.742736 -222.272098)
		(width 0.0889)
		(layer "In11.Cu")
		(net "GND")
	)
	(arc
		(start 355.14915 -222.263462)
		(mid 354.872675 -222.196142)
		(end 354.598478 -222.272098)
		(width 0.0889)
		(layer "In11.Cu")
		(net "GND")
	)
	(arc
		(start 383.450084 -221.133924)
		(mid 383.402405 -221.316824)
		(end 383.271522 -221.453202)
		(width 0.0889)
		(layer "In11.Cu")
		(net "GND")
	)
	(arc
		(start 374.88495 -222.263462)
		(mid 374.608475 -222.196142)
		(end 374.334278 -222.272098)
		(width 0.0889)
		(layer "In11.Cu")
		(net "GND")
	)
	(arc
		(start 380.52375 -222.263462)
		(mid 380.247275 -222.196142)
		(end 379.973078 -222.272098)
		(width 0.0889)
		(layer "In11.Cu")
		(net "GND")
	)
	(arc
		(start 372.06555 -222.263462)
		(mid 371.789075 -222.196142)
		(end 371.514878 -222.272098)
		(width 0.0889)
		(layer "In11.Cu")
		(net "GND")
	)
	(arc
		(start 366.42675 -222.263462)
		(mid 366.150275 -222.196142)
		(end 365.876078 -222.272098)
		(width 0.0889)
		(layer "In11.Cu")
		(net "GND")
	)
	(arc
		(start 383.919984 -220.319854)
		(mid 383.872305 -220.502754)
		(end 383.741422 -220.639132)
		(width 0.0889)
		(layer "In11.Cu")
		(net "GND")
	)
	(arc
		(start 383.732532 -220.644212)
		(mid 383.530246 -220.843193)
		(end 383.450084 -221.115382)
		(width 0.0889)
		(layer "In11.Cu")
		(net "GND")
	)
	(arc
		(start 355.538278 -222.272098)
		(mid 355.35108 -222.322241)
		(end 355.163882 -222.272098)
		(width 0.0889)
		(layer "In11.Cu")
		(net "GND")
	)
	(arc
		(start 379.58395 -222.263462)
		(mid 379.307475 -222.196142)
		(end 379.033278 -222.272098)
		(width 0.0889)
		(layer "In11.Cu")
		(net "GND")
	)
	(arc
		(start 374.334278 -222.272098)
		(mid 374.14708 -222.322241)
		(end 373.959882 -222.272098)
		(width 0.0889)
		(layer "In11.Cu")
		(net "GND")
	)
	(arc
		(start 349.617284 -227.667058)
		(mid 349.698195 -227.937186)
		(end 349.899478 -228.134672)
		(width 0.0889)
		(layer "In11.Cu")
		(net "GND")
	)
	(arc
		(start 350.935036 -228.948488)
		(mid 351.11598 -228.898397)
		(end 351.29851 -228.942392)
		(width 0.0889)
		(layer "In11.Cu")
		(net "GND")
	)
	(arc
		(start 354.20935 -222.263462)
		(mid 353.932875 -222.196142)
		(end 353.658678 -222.272098)
		(width 0.0889)
		(layer "In11.Cu")
		(net "GND")
	)
	(arc
		(start 362.682536 -222.272098)
		(mid 362.399834 -222.196322)
		(end 362.117132 -222.272098)
		(width 0.0889)
		(layer "In11.Cu")
		(net "GND")
	)
	(arc
		(start 365.48695 -222.263462)
		(mid 365.210475 -222.196142)
		(end 364.936278 -222.272098)
		(width 0.0889)
		(layer "In11.Cu")
		(net "GND")
	)
	(arc
		(start 369.635278 -222.272098)
		(mid 369.44808 -222.322241)
		(end 369.260882 -222.272098)
		(width 0.0889)
		(layer "In11.Cu")
		(net "GND")
	)
	(arc
		(start 349.438722 -227.325682)
		(mid 349.569636 -227.462042)
		(end 349.617284 -227.64496)
		(width 0.0889)
		(layer "In11.Cu")
		(net "GND")
	)
	(arc
		(start 353.26955 -222.263462)
		(mid 352.993075 -222.196142)
		(end 352.718878 -222.272098)
		(width 0.0889)
		(layer "In11.Cu")
		(net "GND")
	)
	(arc
		(start 363.996478 -222.272098)
		(mid 363.80928 -222.322241)
		(end 363.622082 -222.272098)
		(width 0.0889)
		(layer "In11.Cu")
		(net "GND")
	)
	(arc
		(start 357.973122 -222.266002)
		(mid 357.69469 -222.196156)
		(end 357.417878 -222.272098)
		(width 0.0889)
		(layer "In11.Cu")
		(net "GND")
	)
	(arc
		(start 349.908368 -228.139752)
		(mid 350.039282 -228.276112)
		(end 350.08693 -228.45903)
		(width 0.0889)
		(layer "In11.Cu")
		(net "GND")
	)
	(arc
		(start 364.54715 -222.263462)
		(mid 364.270675 -222.196142)
		(end 363.996478 -222.272098)
		(width 0.0889)
		(layer "In11.Cu")
		(net "GND")
	)
	(arc
		(start 378.64415 -222.263462)
		(mid 378.367675 -222.196142)
		(end 378.093478 -222.272098)
		(width 0.0889)
		(layer "In11.Cu")
		(net "GND")
	)
	(arc
		(start 373.394478 -222.272098)
		(mid 373.20728 -222.322241)
		(end 373.020082 -222.272098)
		(width 0.0889)
		(layer "In11.Cu")
		(net "GND")
	)
	(arc
		(start 385.329684 -217.878406)
		(mid 385.282005 -218.061306)
		(end 385.151122 -218.197684)
		(width 0.0889)
		(layer "In11.Cu")
		(net "GND")
	)
	(segment
		(start 279.5778 -70.050152)
		(end 280.423112 -70.895464)
		(width 0.508)
		(layer "In13.Cu")
		(net "GND")
	)
	(segment
		(start 99.14128 -344.727022)
		(end 99.839018 -344.029284)
		(width 0.508)
		(layer "In13.Cu")
		(net "GND")
	)
	(segment
		(start 354.641658 -343.204546)
		(end 355.339396 -343.902284)
		(width 0.508)
		(layer "In13.Cu")
		(net "GND")
	)
	(segment
		(start 347.081094 -343.204546)
		(end 347.778832 -343.902284)
		(width 0.508)
		(layer "In13.Cu")
		(net "GND")
	)
	(segment
		(start 366.786922 -350.357948)
		(end 367.48466 -349.66021)
		(width 0.508)
		(layer "In13.Cu")
		(net "GND")
	)
	(segment
		(start 369.907566 -344.600022)
		(end 370.605304 -343.902284)
		(width 0.508)
		(layer "In13.Cu")
		(net "GND")
	)
	(segment
		(start 329.690222 -66.338704)
		(end 329.690222 -73.135236)
		(width 0.254)
		(layer "In13.Cu")
		(net "GND")
	)
	(segment
		(start 279.6032 -63.877952)
		(end 280.448512 -63.03264)
		(width 0.508)
		(layer "In13.Cu")
		(net "GND")
	)
	(segment
		(start 355.339396 -343.902284)
		(end 356.037134 -343.204546)
		(width 0.508)
		(layer "In13.Cu")
		(net "GND")
	)
	(segment
		(start 99.839018 -344.029284)
		(end 100.536756 -343.331546)
		(width 0.508)
		(layer "In13.Cu")
		(net "GND")
	)
	(segment
		(start 118.984522 -350.434148)
		(end 119.68226 -351.131886)
		(width 0.508)
		(layer "In13.Cu")
		(net "GND")
	)
	(segment
		(start 278.732488 -70.895464)
		(end 279.5778 -70.050152)
		(width 0.508)
		(layer "In13.Cu")
		(net "GND")
	)
	(segment
		(start 141.339316 -366.773206)
		(end 142.045944 -366.066578)
		(width 0.3556)
		(layer "In13.Cu")
		(net "GND")
	)
	(segment
		(start 122.565922 -343.906348)
		(end 123.26366 -343.20861)
		(width 0.508)
		(layer "In13.Cu")
		(net "GND")
	)
	(segment
		(start 142.045944 -366.066578)
		(end 142.752572 -365.35995)
		(width 0.3556)
		(layer "In13.Cu")
		(net "GND")
	)
	(segment
		(start 426.624496 -157.843728)
		(end 427.452028 -157.016196)
		(width 0.508)
		(layer "In13.Cu")
		(net "GND")
	)
	(segment
		(start 329.690222 -73.135236)
		(end 328.462386 -74.363072)
		(width 0.254)
		(layer "In13.Cu")
		(net "GND")
	)
	(segment
		(start 331.424534 -60.35802)
		(end 331.424534 -61.268864)
		(width 0.254)
		(layer "In13.Cu")
		(net "GND")
	)
	(segment
		(start 330.124308 -65.904618)
		(end 329.690222 -66.338704)
		(width 0.254)
		(layer "In13.Cu")
		(net "GND")
	)
	(segment
		(start 354.641658 -344.600022)
		(end 355.339396 -343.902284)
		(width 0.508)
		(layer "In13.Cu")
		(net "GND")
	)
	(segment
		(start 426.624496 -170.781218)
		(end 427.452028 -169.953686)
		(width 0.508)
		(layer "In13.Cu")
		(net "GND")
	)
	(segment
		(start 121.868184 -343.20861)
		(end 122.565922 -343.906348)
		(width 0.508)
		(layer "In13.Cu")
		(net "GND")
	)
	(segment
		(start 114.407188 -344.727022)
		(end 115.104926 -344.029284)
		(width 0.508)
		(layer "In13.Cu")
		(net "GND")
	)
	(segment
		(start 366.786922 -350.357948)
		(end 367.48466 -351.055686)
		(width 0.508)
		(layer "In13.Cu")
		(net "GND")
	)
	(segment
		(start 427.452028 -169.953686)
		(end 428.27956 -169.126154)
		(width 0.508)
		(layer "In13.Cu")
		(net "GND")
	)
	(segment
		(start 347.081094 -344.600022)
		(end 347.778832 -343.902284)
		(width 0.508)
		(layer "In13.Cu")
		(net "GND")
	)
	(segment
		(start 106.701844 -343.331546)
		(end 107.399582 -344.029284)
		(width 0.508)
		(layer "In13.Cu")
		(net "GND")
	)
	(segment
		(start 122.565922 -343.906348)
		(end 123.26366 -344.604086)
		(width 0.508)
		(layer "In13.Cu")
		(net "GND")
	)
	(segment
		(start 370.605304 -343.902284)
		(end 371.303042 -343.204546)
		(width 0.508)
		(layer "In13.Cu")
		(net "GND")
	)
	(segment
		(start 355.339396 -343.902284)
		(end 356.037134 -344.600022)
		(width 0.508)
		(layer "In13.Cu")
		(net "GND")
	)
	(segment
		(start 141.339316 -365.35995)
		(end 142.045944 -366.066578)
		(width 0.3556)
		(layer "In13.Cu")
		(net "GND")
	)
	(segment
		(start 363.04474 -343.902284)
		(end 363.742478 -343.204546)
		(width 0.508)
		(layer "In13.Cu")
		(net "GND")
	)
	(segment
		(start 115.104926 -344.029284)
		(end 115.802664 -343.331546)
		(width 0.508)
		(layer "In13.Cu")
		(net "GND")
	)
	(segment
		(start 363.04474 -343.902284)
		(end 363.742478 -344.600022)
		(width 0.508)
		(layer "In13.Cu")
		(net "GND")
	)
	(segment
		(start 347.778832 -343.902284)
		(end 348.47657 -344.600022)
		(width 0.508)
		(layer "In13.Cu")
		(net "GND")
	)
	(segment
		(start 362.347002 -343.204546)
		(end 363.04474 -343.902284)
		(width 0.508)
		(layer "In13.Cu")
		(net "GND")
	)
	(segment
		(start 427.452028 -169.953686)
		(end 428.27956 -170.781218)
		(width 0.508)
		(layer "In13.Cu")
		(net "GND")
	)
	(segment
		(start 107.399582 -344.029284)
		(end 108.09732 -344.727022)
		(width 0.508)
		(layer "In13.Cu")
		(net "GND")
	)
	(segment
		(start 121.868184 -344.604086)
		(end 122.565922 -343.906348)
		(width 0.508)
		(layer "In13.Cu")
		(net "GND")
	)
	(segment
		(start 99.839018 -344.029284)
		(end 100.536756 -344.727022)
		(width 0.508)
		(layer "In13.Cu")
		(net "GND")
	)
	(segment
		(start 107.399582 -344.029284)
		(end 108.09732 -343.331546)
		(width 0.508)
		(layer "In13.Cu")
		(net "GND")
	)
	(segment
		(start 118.286784 -351.131886)
		(end 118.984522 -350.434148)
		(width 0.508)
		(layer "In13.Cu")
		(net "GND")
	)
	(segment
		(start 362.347002 -344.600022)
		(end 363.04474 -343.902284)
		(width 0.508)
		(layer "In13.Cu")
		(net "GND")
	)
	(segment
		(start 331.424534 -61.268864)
		(end 330.124308 -62.56909)
		(width 0.254)
		(layer "In13.Cu")
		(net "GND")
	)
	(segment
		(start 114.407188 -343.331546)
		(end 115.104926 -344.029284)
		(width 0.508)
		(layer "In13.Cu")
		(net "GND")
	)
	(segment
		(start 330.124308 -62.56909)
		(end 330.124308 -65.904618)
		(width 0.254)
		(layer "In13.Cu")
		(net "GND")
	)
	(segment
		(start 279.5778 -70.050152)
		(end 280.423112 -69.20484)
		(width 0.508)
		(layer "In13.Cu")
		(net "GND")
	)
	(segment
		(start 278.732488 -69.20484)
		(end 279.5778 -70.050152)
		(width 0.508)
		(layer "In13.Cu")
		(net "GND")
	)
	(segment
		(start 279.6032 -63.877952)
		(end 280.448512 -64.723264)
		(width 0.508)
		(layer "In13.Cu")
		(net "GND")
	)
	(segment
		(start 427.452028 -157.016196)
		(end 428.27956 -157.843728)
		(width 0.508)
		(layer "In13.Cu")
		(net "GND")
	)
	(segment
		(start 370.605304 -343.902284)
		(end 371.303042 -344.600022)
		(width 0.508)
		(layer "In13.Cu")
		(net "GND")
	)
	(segment
		(start 118.984522 -350.434148)
		(end 119.68226 -349.73641)
		(width 0.508)
		(layer "In13.Cu")
		(net "GND")
	)
	(segment
		(start 427.452028 -157.016196)
		(end 428.27956 -156.188664)
		(width 0.508)
		(layer "In13.Cu")
		(net "GND")
	)
	(segment
		(start 115.104926 -344.029284)
		(end 115.802664 -344.727022)
		(width 0.508)
		(layer "In13.Cu")
		(net "GND")
	)
	(segment
		(start 328.462386 -74.363072)
		(end 327.91527 -74.363072)
		(width 0.254)
		(layer "In13.Cu")
		(net "GND")
	)
	(segment
		(start 106.701844 -344.727022)
		(end 107.399582 -344.029284)
		(width 0.508)
		(layer "In13.Cu")
		(net "GND")
	)
	(segment
		(start 336.766408 -54.558946)
		(end 335.210658 -54.558946)
		(width 0.254)
		(layer "In13.Cu")
		(net "GND")
	)
	(segment
		(start 369.907566 -343.204546)
		(end 370.605304 -343.902284)
		(width 0.508)
		(layer "In13.Cu")
		(net "GND")
	)
	(segment
		(start 334.391508 -57.391046)
		(end 331.424534 -60.35802)
		(width 0.254)
		(layer "In13.Cu")
		(net "GND")
	)
	(segment
		(start 118.286784 -349.73641)
		(end 118.984522 -350.434148)
		(width 0.508)
		(layer "In13.Cu")
		(net "GND")
	)
	(segment
		(start 278.757888 -64.723264)
		(end 279.6032 -63.877952)
		(width 0.508)
		(layer "In13.Cu")
		(net "GND")
	)
	(segment
		(start 347.778832 -343.902284)
		(end 348.47657 -343.204546)
		(width 0.508)
		(layer "In13.Cu")
		(net "GND")
	)
	(segment
		(start 334.391508 -55.378096)
		(end 334.391508 -57.391046)
		(width 0.254)
		(layer "In13.Cu")
		(net "GND")
	)
	(segment
		(start 327.91527 -74.363072)
		(end 327.66127 -74.617072)
		(width 0.254)
		(layer "In13.Cu")
		(net "GND")
	)
	(segment
		(start 366.089184 -349.66021)
		(end 366.786922 -350.357948)
		(width 0.508)
		(layer "In13.Cu")
		(net "GND")
	)
	(segment
		(start 335.210658 -54.558946)
		(end 334.391508 -55.378096)
		(width 0.254)
		(layer "In13.Cu")
		(net "GND")
	)
	(segment
		(start 99.14128 -343.331546)
		(end 99.839018 -344.029284)
		(width 0.508)
		(layer "In13.Cu")
		(net "GND")
	)
	(segment
		(start 426.624496 -156.188664)
		(end 427.452028 -157.016196)
		(width 0.508)
		(layer "In13.Cu")
		(net "GND")
	)
	(segment
		(start 366.089184 -351.055686)
		(end 366.786922 -350.357948)
		(width 0.508)
		(layer "In13.Cu")
		(net "GND")
	)
	(segment
		(start 426.624496 -169.126154)
		(end 427.452028 -169.953686)
		(width 0.508)
		(layer "In13.Cu")
		(net "GND")
	)
	(segment
		(start 278.757888 -63.03264)
		(end 279.6032 -63.877952)
		(width 0.508)
		(layer "In13.Cu")
		(net "GND")
	)
	(segment
		(start 347.081094 -344.600022)
		(end 347.778832 -343.902284)
		(width 0.508)
		(layer "In15.Cu")
		(net "GND")
	)
	(segment
		(start 43.672252 -162.588956)
		(end 44.36999 -161.891218)
		(width 0.508)
		(layer "In15.Cu")
		(net "GND")
	)
	(segment
		(start 99.14128 -344.727022)
		(end 99.839018 -344.029284)
		(width 0.508)
		(layer "In15.Cu")
		(net "GND")
	)
	(segment
		(start 106.701844 -344.727022)
		(end 107.399582 -344.029284)
		(width 0.508)
		(layer "In15.Cu")
		(net "GND")
	)
	(segment
		(start 99.839018 -344.029284)
		(end 100.536756 -343.331546)
		(width 0.508)
		(layer "In15.Cu")
		(net "GND")
	)
	(segment
		(start 99.839018 -344.029284)
		(end 100.536756 -344.727022)
		(width 0.508)
		(layer "In15.Cu")
		(net "GND")
	)
	(segment
		(start 115.104926 -344.029284)
		(end 115.802664 -344.727022)
		(width 0.508)
		(layer "In15.Cu")
		(net "GND")
	)
	(segment
		(start 118.286784 -349.73641)
		(end 118.984522 -350.434148)
		(width 0.508)
		(layer "In15.Cu")
		(net "GND")
	)
	(segment
		(start 362.347002 -344.600022)
		(end 363.04474 -343.902284)
		(width 0.508)
		(layer "In15.Cu")
		(net "GND")
	)
	(segment
		(start 366.089184 -351.055686)
		(end 366.786922 -350.357948)
		(width 0.508)
		(layer "In15.Cu")
		(net "GND")
	)
	(segment
		(start 43.672252 -161.19348)
		(end 44.36999 -161.891218)
		(width 0.508)
		(layer "In15.Cu")
		(net "GND")
	)
	(segment
		(start 369.907566 -343.204546)
		(end 370.605304 -343.902284)
		(width 0.508)
		(layer "In15.Cu")
		(net "GND")
	)
	(segment
		(start 106.701844 -343.331546)
		(end 107.399582 -344.029284)
		(width 0.508)
		(layer "In15.Cu")
		(net "GND")
	)
	(segment
		(start 114.407188 -343.331546)
		(end 115.104926 -344.029284)
		(width 0.508)
		(layer "In15.Cu")
		(net "GND")
	)
	(segment
		(start 107.399582 -344.029284)
		(end 108.09732 -344.727022)
		(width 0.508)
		(layer "In15.Cu")
		(net "GND")
	)
	(segment
		(start 369.907566 -344.600022)
		(end 370.605304 -343.902284)
		(width 0.508)
		(layer "In15.Cu")
		(net "GND")
	)
	(segment
		(start 355.339396 -343.902284)
		(end 356.037134 -344.600022)
		(width 0.508)
		(layer "In15.Cu")
		(net "GND")
	)
	(segment
		(start 347.081094 -343.204546)
		(end 347.778832 -343.902284)
		(width 0.508)
		(layer "In15.Cu")
		(net "GND")
	)
	(segment
		(start 107.399582 -344.029284)
		(end 108.09732 -343.331546)
		(width 0.508)
		(layer "In15.Cu")
		(net "GND")
	)
	(segment
		(start 347.778832 -343.902284)
		(end 348.47657 -343.204546)
		(width 0.508)
		(layer "In15.Cu")
		(net "GND")
	)
	(segment
		(start 362.347002 -343.204546)
		(end 363.04474 -343.902284)
		(width 0.508)
		(layer "In15.Cu")
		(net "GND")
	)
	(segment
		(start 366.786922 -350.357948)
		(end 367.48466 -351.055686)
		(width 0.508)
		(layer "In15.Cu")
		(net "GND")
	)
	(segment
		(start 142.045944 -366.066578)
		(end 142.752572 -365.35995)
		(width 0.381)
		(layer "In15.Cu")
		(net "GND")
	)
	(segment
		(start 121.868184 -344.604086)
		(end 122.565922 -343.906348)
		(width 0.508)
		(layer "In15.Cu")
		(net "GND")
	)
	(segment
		(start 44.295822 -169.801794)
		(end 44.99356 -170.499532)
		(width 0.508)
		(layer "In15.Cu")
		(net "GND")
	)
	(segment
		(start 370.605304 -343.902284)
		(end 371.303042 -344.600022)
		(width 0.508)
		(layer "In15.Cu")
		(net "GND")
	)
	(segment
		(start 141.339316 -366.773206)
		(end 142.045944 -366.066578)
		(width 0.381)
		(layer "In15.Cu")
		(net "GND")
	)
	(segment
		(start 142.045944 -366.066578)
		(end 142.752572 -366.773206)
		(width 0.381)
		(layer "In15.Cu")
		(net "GND")
	)
	(segment
		(start 44.36999 -161.891218)
		(end 45.067728 -162.588956)
		(width 0.508)
		(layer "In15.Cu")
		(net "GND")
	)
	(segment
		(start 118.286784 -351.131886)
		(end 118.984522 -350.434148)
		(width 0.508)
		(layer "In15.Cu")
		(net "GND")
	)
	(segment
		(start 354.641658 -344.600022)
		(end 355.339396 -343.902284)
		(width 0.508)
		(layer "In15.Cu")
		(net "GND")
	)
	(segment
		(start 44.36999 -161.891218)
		(end 45.067728 -161.19348)
		(width 0.508)
		(layer "In15.Cu")
		(net "GND")
	)
	(segment
		(start 355.339396 -343.902284)
		(end 356.037134 -343.204546)
		(width 0.508)
		(layer "In15.Cu")
		(net "GND")
	)
	(segment
		(start 44.295822 -169.801794)
		(end 44.99356 -169.104056)
		(width 0.508)
		(layer "In15.Cu")
		(net "GND")
	)
	(segment
		(start 114.407188 -344.727022)
		(end 115.104926 -344.029284)
		(width 0.508)
		(layer "In15.Cu")
		(net "GND")
	)
	(segment
		(start 366.786922 -350.357948)
		(end 367.48466 -349.66021)
		(width 0.508)
		(layer "In15.Cu")
		(net "GND")
	)
	(segment
		(start 363.04474 -343.902284)
		(end 363.742478 -344.600022)
		(width 0.508)
		(layer "In15.Cu")
		(net "GND")
	)
	(segment
		(start 141.339316 -365.35995)
		(end 142.045944 -366.066578)
		(width 0.381)
		(layer "In15.Cu")
		(net "GND")
	)
	(segment
		(start 43.598084 -169.104056)
		(end 44.295822 -169.801794)
		(width 0.508)
		(layer "In15.Cu")
		(net "GND")
	)
	(segment
		(start 366.089184 -349.66021)
		(end 366.786922 -350.357948)
		(width 0.508)
		(layer "In15.Cu")
		(net "GND")
	)
	(segment
		(start 363.04474 -343.902284)
		(end 363.742478 -343.204546)
		(width 0.508)
		(layer "In15.Cu")
		(net "GND")
	)
	(segment
		(start 354.641658 -343.204546)
		(end 355.339396 -343.902284)
		(width 0.508)
		(layer "In15.Cu")
		(net "GND")
	)
	(segment
		(start 118.984522 -350.434148)
		(end 119.68226 -351.131886)
		(width 0.508)
		(layer "In15.Cu")
		(net "GND")
	)
	(segment
		(start 347.778832 -343.902284)
		(end 348.47657 -344.600022)
		(width 0.508)
		(layer "In15.Cu")
		(net "GND")
	)
	(segment
		(start 122.565922 -343.906348)
		(end 123.26366 -343.20861)
		(width 0.508)
		(layer "In15.Cu")
		(net "GND")
	)
	(segment
		(start 115.104926 -344.029284)
		(end 115.802664 -343.331546)
		(width 0.508)
		(layer "In15.Cu")
		(net "GND")
	)
	(segment
		(start 370.605304 -343.902284)
		(end 371.303042 -343.204546)
		(width 0.508)
		(layer "In15.Cu")
		(net "GND")
	)
	(segment
		(start 99.14128 -343.331546)
		(end 99.839018 -344.029284)
		(width 0.508)
		(layer "In15.Cu")
		(net "GND")
	)
	(segment
		(start 118.984522 -350.434148)
		(end 119.68226 -349.73641)
		(width 0.508)
		(layer "In15.Cu")
		(net "GND")
	)
	(segment
		(start 43.598084 -170.499532)
		(end 44.295822 -169.801794)
		(width 0.508)
		(layer "In15.Cu")
		(net "GND")
	)
	(segment
		(start 121.868184 -343.20861)
		(end 122.565922 -343.906348)
		(width 0.508)
		(layer "In15.Cu")
		(net "GND")
	)
	(segment
		(start 122.565922 -343.906348)
		(end 123.26366 -344.604086)
		(width 0.508)
		(layer "In15.Cu")
		(net "GND")
	)
	(segment
		(start 334.05064 -43.281346)
		(end 333.511398 -43.281346)
		(width 0.12954)
		(layer "F.Cu")
		(net "FM_XTAL_INPUT_FREQUENCY_1_MGPIO")
	)
	(via
		(at 337.051396 -36.661852)
		(size 0.6604)
		(drill 0.3302)
		(layers "F.Cu" "B.Cu")
		(net "FM_XTAL_INPUT_FREQUENCY_1_MGPIO")
	)
	(via
		(at 333.511398 -43.281346)
		(size 0.4572)
		(drill 0.2032)
		(layers "F.Cu" "B.Cu")
		(net "FM_XTAL_INPUT_FREQUENCY_1_MGPIO")
	)
	(segment
		(start 337.051396 -36.177982)
		(end 339.008466 -34.220912)
		(width 0.12954)
		(layer "B.Cu")
		(net "FM_XTAL_INPUT_FREQUENCY_1_MGPIO")
	)
	(segment
		(start 339.008466 -34.220912)
		(end 339.008466 -33.29305)
		(width 0.12954)
		(layer "B.Cu")
		(net "FM_XTAL_INPUT_FREQUENCY_1_MGPIO")
	)
	(segment
		(start 333.511144 -42.968672)
		(end 333.575914 -42.903648)
		(width 0.0889)
		(layer "B.Cu")
		(net "FM_XTAL_INPUT_FREQUENCY_1_MGPIO")
	)
	(segment
		(start 334.000856 -40.179244)
		(end 333.991966 -40.16375)
		(width 0.0889)
		(layer "B.Cu")
		(net "FM_XTAL_INPUT_FREQUENCY_1_MGPIO")
	)
	(segment
		(start 335.07934 -38.707568)
		(end 335.565496 -38.707568)
		(width 0.12954)
		(layer "B.Cu")
		(net "FM_XTAL_INPUT_FREQUENCY_1_MGPIO")
	)
	(segment
		(start 339.008466 -33.29305)
		(end 338.553044 -32.837628)
		(width 0.12954)
		(layer "B.Cu")
		(net "FM_XTAL_INPUT_FREQUENCY_1_MGPIO")
	)
	(segment
		(start 337.051396 -36.661852)
		(end 337.051396 -36.177982)
		(width 0.12954)
		(layer "B.Cu")
		(net "FM_XTAL_INPUT_FREQUENCY_1_MGPIO")
	)
	(segment
		(start 335.565496 -38.707568)
		(end 337.051396 -37.221668)
		(width 0.12954)
		(layer "B.Cu")
		(net "FM_XTAL_INPUT_FREQUENCY_1_MGPIO")
	)
	(segment
		(start 337.051396 -37.221668)
		(end 337.051396 -36.661852)
		(width 0.12954)
		(layer "B.Cu")
		(net "FM_XTAL_INPUT_FREQUENCY_1_MGPIO")
	)
	(segment
		(start 333.511398 -43.281346)
		(end 333.511144 -42.968672)
		(width 0.0889)
		(layer "B.Cu")
		(net "FM_XTAL_INPUT_FREQUENCY_1_MGPIO")
	)
	(segment
		(start 333.99222 -41.699942)
		(end 334.00111 -41.684448)
		(width 0.0889)
		(layer "B.Cu")
		(net "FM_XTAL_INPUT_FREQUENCY_1_MGPIO")
	)
	(segment
		(start 334.008984 -40.19296)
		(end 334.000856 -40.179244)
		(width 0.0889)
		(layer "B.Cu")
		(net "FM_XTAL_INPUT_FREQUENCY_1_MGPIO")
	)
	(segment
		(start 334.060038 -39.72687)
		(end 334.602328 -39.18458)
		(width 0.0889)
		(layer "B.Cu")
		(net "FM_XTAL_INPUT_FREQUENCY_1_MGPIO")
	)
	(segment
		(start 334.602328 -39.18458)
		(end 335.07934 -38.707568)
		(width 0.12954)
		(layer "B.Cu")
		(net "FM_XTAL_INPUT_FREQUENCY_1_MGPIO")
	)
	(arc
		(start 334.000602 -42.624248)
		(mid 334.076276 -42.341546)
		(end 334.000602 -42.058844)
		(width 0.0889)
		(layer "B.Cu")
		(net "FM_XTAL_INPUT_FREQUENCY_1_MGPIO")
	)
	(arc
		(start 334.00111 -41.119044)
		(mid 333.950967 -40.931846)
		(end 334.00111 -40.744648)
		(width 0.0889)
		(layer "B.Cu")
		(net "FM_XTAL_INPUT_FREQUENCY_1_MGPIO")
	)
	(arc
		(start 334.000602 -42.058844)
		(mid 333.95063 -41.880455)
		(end 333.99222 -41.699942)
		(width 0.0889)
		(layer "B.Cu")
		(net "FM_XTAL_INPUT_FREQUENCY_1_MGPIO")
	)
	(arc
		(start 333.575914 -42.903648)
		(mid 333.821402 -42.814324)
		(end 334.000602 -42.624248)
		(width 0.0889)
		(layer "B.Cu")
		(net "FM_XTAL_INPUT_FREQUENCY_1_MGPIO")
	)
	(arc
		(start 333.991966 -40.16375)
		(mid 333.954816 -39.93424)
		(end 334.060038 -39.72687)
		(width 0.0889)
		(layer "B.Cu")
		(net "FM_XTAL_INPUT_FREQUENCY_1_MGPIO")
	)
	(arc
		(start 334.00111 -40.744648)
		(mid 334.076921 -40.469821)
		(end 334.008984 -40.19296)
		(width 0.0889)
		(layer "B.Cu")
		(net "FM_XTAL_INPUT_FREQUENCY_1_MGPIO")
	)
	(arc
		(start 334.00111 -41.684448)
		(mid 334.076852 -41.401746)
		(end 334.00111 -41.119044)
		(width 0.0889)
		(layer "B.Cu")
		(net "FM_XTAL_INPUT_FREQUENCY_1_MGPIO")
	)
	(segment
		(start 334.864456 -39.992046)
		(end 334.325214 -39.992046)
		(width 0.12954)
		(layer "F.Cu")
		(net "FM_XTAL_INPUT_FREQUENCY_0_MGPIO")
	)
	(via
		(at 334.325214 -39.992046)
		(size 0.4572)
		(drill 0.2032)
		(layers "F.Cu" "B.Cu")
		(net "FM_XTAL_INPUT_FREQUENCY_0_MGPIO")
	)
	(via
		(at 338.328508 -36.141406)
		(size 0.6604)
		(drill 0.3302)
		(layers "F.Cu" "B.Cu")
		(net "FM_XTAL_INPUT_FREQUENCY_0_MGPIO")
	)
	(segment
		(start 334.80883 -39.794942)
		(end 334.80883 -39.426134)
		(width 0.12954)
		(layer "B.Cu")
		(net "FM_XTAL_INPUT_FREQUENCY_0_MGPIO")
	)
	(segment
		(start 338.328508 -36.141406)
		(end 338.328508 -35.369246)
		(width 0.12954)
		(layer "B.Cu")
		(net "FM_XTAL_INPUT_FREQUENCY_0_MGPIO")
	)
	(segment
		(start 334.80883 -39.426134)
		(end 335.222596 -39.012368)
		(width 0.12954)
		(layer "B.Cu")
		(net "FM_XTAL_INPUT_FREQUENCY_0_MGPIO")
	)
	(segment
		(start 338.328508 -35.369246)
		(end 339.579966 -34.117788)
		(width 0.12954)
		(layer "B.Cu")
		(net "FM_XTAL_INPUT_FREQUENCY_0_MGPIO")
	)
	(segment
		(start 334.611726 -39.992046)
		(end 334.80883 -39.794942)
		(width 0.12954)
		(layer "B.Cu")
		(net "FM_XTAL_INPUT_FREQUENCY_0_MGPIO")
	)
	(segment
		(start 335.222596 -39.012368)
		(end 335.696052 -39.012368)
		(width 0.12954)
		(layer "B.Cu")
		(net "FM_XTAL_INPUT_FREQUENCY_0_MGPIO")
	)
	(segment
		(start 339.579966 -34.117788)
		(end 339.579966 -32.329882)
		(width 0.12954)
		(layer "B.Cu")
		(net "FM_XTAL_INPUT_FREQUENCY_0_MGPIO")
	)
	(segment
		(start 339.579966 -32.329882)
		(end 339.58022 -32.329628)
		(width 0.12954)
		(layer "B.Cu")
		(net "FM_XTAL_INPUT_FREQUENCY_0_MGPIO")
	)
	(segment
		(start 334.325214 -39.992046)
		(end 334.611726 -39.992046)
		(width 0.12954)
		(layer "B.Cu")
		(net "FM_XTAL_INPUT_FREQUENCY_0_MGPIO")
	)
	(segment
		(start 335.696052 -39.012368)
		(end 337.398614 -37.309806)
		(width 0.12954)
		(layer "B.Cu")
		(net "FM_XTAL_INPUT_FREQUENCY_0_MGPIO")
	)
	(segment
		(start 337.398614 -37.309806)
		(end 337.398614 -37.0713)
		(width 0.12954)
		(layer "B.Cu")
		(net "FM_XTAL_INPUT_FREQUENCY_0_MGPIO")
	)
	(segment
		(start 337.398614 -37.0713)
		(end 338.328508 -36.141406)
		(width 0.12954)
		(layer "B.Cu")
		(net "FM_XTAL_INPUT_FREQUENCY_0_MGPIO")
	)
	(segment
		(start 186.955684 -105.775506)
		(end 190.345822 -105.775506)
		(width 0.12954)
		(layer "F.Cu")
		(net "FM_UV_ADR_TRIGGER_R_N")
	)
	(segment
		(start 190.345822 -105.775506)
		(end 190.53048 -105.590848)
		(width 0.12954)
		(layer "F.Cu")
		(net "FM_UV_ADR_TRIGGER_R_N")
	)
	(segment
		(start 191.07785 -105.043478)
		(end 191.07785 -102.325678)
		(width 0.12954)
		(layer "F.Cu")
		(net "FM_UV_ADR_TRIGGER_R_N")
	)
	(segment
		(start 192.25768 -101.145848)
		(end 193.20383 -101.145848)
		(width 0.12954)
		(layer "F.Cu")
		(net "FM_UV_ADR_TRIGGER_R_N")
	)
	(segment
		(start 190.53048 -105.590848)
		(end 191.07785 -105.043478)
		(width 0.12954)
		(layer "F.Cu")
		(net "FM_UV_ADR_TRIGGER_R_N")
	)
	(segment
		(start 191.07785 -102.325678)
		(end 192.25768 -101.145848)
		(width 0.12954)
		(layer "F.Cu")
		(net "FM_UV_ADR_TRIGGER_R_N")
	)
	(via
		(at 190.53048 -105.590848)
		(size 0.762)
		(drill 0.381)
		(layers "F.Cu" "B.Cu")
		(net "FM_UV_ADR_TRIGGER_R_N")
	)
	(segment
		(start 212.360256 -100.74148)
		(end 211.127086 -100.74148)
		(width 0.12954)
		(layer "F.Cu")
		(net "FM_UV_ADR_TRIGGER_N")
	)
	(segment
		(start 207.772 -98.509328)
		(end 209.22488 -99.962208)
		(width 0.12954)
		(layer "F.Cu")
		(net "FM_UV_ADR_TRIGGER_N")
	)
	(segment
		(start 212.360256 -100.74148)
		(end 214.041736 -100.74148)
		(width 0.12954)
		(layer "F.Cu")
		(net "FM_UV_ADR_TRIGGER_N")
	)
	(segment
		(start 200.228708 -99.3394)
		(end 206.375 -99.3394)
		(width 0.12954)
		(layer "F.Cu")
		(net "FM_UV_ADR_TRIGGER_N")
	)
	(segment
		(start 214.50808 -100.74148)
		(end 214.89416 -101.12756)
		(width 0.12954)
		(layer "F.Cu")
		(net "FM_UV_ADR_TRIGGER_N")
	)
	(segment
		(start 209.22488 -99.962208)
		(end 210.378294 -99.962208)
		(width 0.12954)
		(layer "F.Cu")
		(net "FM_UV_ADR_TRIGGER_N")
	)
	(segment
		(start 206.7052 -99.0092)
		(end 206.7052 -98.08845)
		(width 0.12954)
		(layer "F.Cu")
		(net "FM_UV_ADR_TRIGGER_N")
	)
	(segment
		(start 196.12356 -100.528628)
		(end 199.03948 -100.528628)
		(width 0.12954)
		(layer "F.Cu")
		(net "FM_UV_ADR_TRIGGER_N")
	)
	(segment
		(start 194.00393 -101.145848)
		(end 195.50634 -101.145848)
		(width 0.12954)
		(layer "F.Cu")
		(net "FM_UV_ADR_TRIGGER_N")
	)
	(segment
		(start 199.03948 -100.528628)
		(end 200.228708 -99.3394)
		(width 0.12954)
		(layer "F.Cu")
		(net "FM_UV_ADR_TRIGGER_N")
	)
	(segment
		(start 206.7052 -98.08845)
		(end 207.772 -98.08845)
		(width 0.12954)
		(layer "F.Cu")
		(net "FM_UV_ADR_TRIGGER_N")
	)
	(segment
		(start 214.041736 -100.74148)
		(end 214.50808 -100.74148)
		(width 0.12954)
		(layer "F.Cu")
		(net "FM_UV_ADR_TRIGGER_N")
	)
	(segment
		(start 206.375 -99.3394)
		(end 206.7052 -99.0092)
		(width 0.12954)
		(layer "F.Cu")
		(net "FM_UV_ADR_TRIGGER_N")
	)
	(segment
		(start 214.89416 -101.12756)
		(end 214.89416 -101.39934)
		(width 0.12954)
		(layer "F.Cu")
		(net "FM_UV_ADR_TRIGGER_N")
	)
	(segment
		(start 207.772 -98.08845)
		(end 207.772 -98.509328)
		(width 0.12954)
		(layer "F.Cu")
		(net "FM_UV_ADR_TRIGGER_N")
	)
	(segment
		(start 195.50634 -101.145848)
		(end 196.12356 -100.528628)
		(width 0.12954)
		(layer "F.Cu")
		(net "FM_UV_ADR_TRIGGER_N")
	)
	(segment
		(start 210.378294 -99.962208)
		(end 210.960462 -100.544376)
		(width 0.12954)
		(layer "F.Cu")
		(net "FM_UV_ADR_TRIGGER_N")
	)
	(segment
		(start 211.127086 -100.74148)
		(end 210.960462 -100.908104)
		(width 0.12954)
		(layer "F.Cu")
		(net "FM_UV_ADR_TRIGGER_N")
	)
	(segment
		(start 210.960462 -100.544376)
		(end 210.960462 -100.908104)
		(width 0.12954)
		(layer "F.Cu")
		(net "FM_UV_ADR_TRIGGER_N")
	)
	(via
		(at 212.360256 -100.74148)
		(size 0.762)
		(drill 0.381)
		(layers "F.Cu" "B.Cu")
		(net "FM_UV_ADR_TRIGGER_N")
	)
	(via
		(at 214.89416 -101.39934)
		(size 0.508)
		(drill 0.254)
		(layers "F.Cu" "B.Cu")
		(net "FM_UV_ADR_TRIGGER_N")
	)
	(segment
		(start 166.52748 -108.118148)
		(end 166.584884 -108.175552)
		(width 0.12954)
		(layer "F.Cu")
		(net "FM_TPM_PRSNT_R_N")
	)
	(segment
		(start 166.34968 -108.295948)
		(end 166.52748 -108.118148)
		(width 0.12954)
		(layer "F.Cu")
		(net "FM_TPM_PRSNT_R_N")
	)
	(segment
		(start 165.04793 -108.295948)
		(end 166.34968 -108.295948)
		(width 0.12954)
		(layer "F.Cu")
		(net "FM_TPM_PRSNT_R_N")
	)
	(segment
		(start 166.584884 -108.175552)
		(end 170.155616 -108.175552)
		(width 0.12954)
		(layer "F.Cu")
		(net "FM_TPM_PRSNT_R_N")
	)
	(via
		(at 166.52748 -108.118148)
		(size 0.762)
		(drill 0.381)
		(layers "F.Cu" "B.Cu")
		(net "FM_TPM_PRSNT_R_N")
	)
	(segment
		(start 164.24783 -108.295948)
		(end 163.63188 -108.295948)
		(width 0.12954)
		(layer "F.Cu")
		(net "FM_TPM_PRSNT_N")
	)
	(segment
		(start 341.006176 -39.992046)
		(end 341.37727 -39.992046)
		(width 0.12954)
		(layer "F.Cu")
		(net "FM_TPM_PRSNT_N")
	)
	(segment
		(start 340.865968 -39.851838)
		(end 341.006176 -39.992046)
		(width 0.12954)
		(layer "F.Cu")
		(net "FM_TPM_PRSNT_N")
	)
	(via
		(at 236.339888 -62.507622)
		(size 0.508)
		(drill 0.254)
		(layers "F.Cu" "B.Cu")
		(net "FM_TPM_PRSNT_N")
	)
	(via
		(at 163.63188 -108.295948)
		(size 0.508)
		(drill 0.254)
		(layers "F.Cu" "B.Cu")
		(net "FM_TPM_PRSNT_N")
	)
	(via
		(at 171.123102 -60.38215)
		(size 0.508)
		(drill 0.254)
		(layers "F.Cu" "B.Cu")
		(net "FM_TPM_PRSNT_N")
	)
	(via
		(at 340.865968 -39.851838)
		(size 0.4572)
		(drill 0.2032)
		(layers "F.Cu" "B.Cu")
		(net "FM_TPM_PRSNT_N")
	)
	(segment
		(start 312.204862 -35.299396)
		(end 313.04484 -36.139374)
		(width 0.127)
		(layer "In4.Cu")
		(net "FM_TPM_PRSNT_N")
	)
	(segment
		(start 269.06982 -64.359028)
		(end 271.63014 -63.298324)
		(width 0.127)
		(layer "In4.Cu")
		(net "FM_TPM_PRSNT_N")
	)
	(segment
		(start 293.48557 -38.375844)
		(end 306.215542 -38.375844)
		(width 0.127)
		(layer "In4.Cu")
		(net "FM_TPM_PRSNT_N")
	)
	(segment
		(start 237.94466 -64.359028)
		(end 269.06982 -64.359028)
		(width 0.127)
		(layer "In4.Cu")
		(net "FM_TPM_PRSNT_N")
	)
	(segment
		(start 327.741026 -38.842442)
		(end 335.87182 -38.842442)
		(width 0.127)
		(layer "In4.Cu")
		(net "FM_TPM_PRSNT_N")
	)
	(segment
		(start 318.65189 -37.32403)
		(end 320.895726 -37.32403)
		(width 0.127)
		(layer "In4.Cu")
		(net "FM_TPM_PRSNT_N")
	)
	(segment
		(start 236.339888 -62.754256)
		(end 237.94466 -64.359028)
		(width 0.127)
		(layer "In4.Cu")
		(net "FM_TPM_PRSNT_N")
	)
	(segment
		(start 276.668484 -59.931808)
		(end 278.71928 -57.881012)
		(width 0.127)
		(layer "In4.Cu")
		(net "FM_TPM_PRSNT_N")
	)
	(segment
		(start 313.04484 -36.139374)
		(end 317.467234 -36.139374)
		(width 0.127)
		(layer "In4.Cu")
		(net "FM_TPM_PRSNT_N")
	)
	(segment
		(start 339.358732 -38.003226)
		(end 340.865968 -39.510462)
		(width 0.127)
		(layer "In4.Cu")
		(net "FM_TPM_PRSNT_N")
	)
	(segment
		(start 320.895726 -37.32403)
		(end 322.67271 -39.101014)
		(width 0.127)
		(layer "In4.Cu")
		(net "FM_TPM_PRSNT_N")
	)
	(segment
		(start 317.467234 -36.139374)
		(end 318.65189 -37.32403)
		(width 0.127)
		(layer "In4.Cu")
		(net "FM_TPM_PRSNT_N")
	)
	(segment
		(start 236.339888 -62.507622)
		(end 236.339888 -62.754256)
		(width 0.127)
		(layer "In4.Cu")
		(net "FM_TPM_PRSNT_N")
	)
	(segment
		(start 309.29199 -35.299396)
		(end 312.204862 -35.299396)
		(width 0.127)
		(layer "In4.Cu")
		(net "FM_TPM_PRSNT_N")
	)
	(segment
		(start 340.865968 -39.510462)
		(end 340.865968 -39.851838)
		(width 0.127)
		(layer "In4.Cu")
		(net "FM_TPM_PRSNT_N")
	)
	(segment
		(start 327.482454 -39.101014)
		(end 327.741026 -38.842442)
		(width 0.127)
		(layer "In4.Cu")
		(net "FM_TPM_PRSNT_N")
	)
	(segment
		(start 278.71928 -57.881012)
		(end 282.070302 -49.791112)
		(width 0.127)
		(layer "In4.Cu")
		(net "FM_TPM_PRSNT_N")
	)
	(segment
		(start 271.63014 -63.298324)
		(end 276.668484 -59.931808)
		(width 0.127)
		(layer "In4.Cu")
		(net "FM_TPM_PRSNT_N")
	)
	(segment
		(start 282.070302 -49.791112)
		(end 293.48557 -38.375844)
		(width 0.127)
		(layer "In4.Cu")
		(net "FM_TPM_PRSNT_N")
	)
	(segment
		(start 336.711036 -38.003226)
		(end 339.358732 -38.003226)
		(width 0.127)
		(layer "In4.Cu")
		(net "FM_TPM_PRSNT_N")
	)
	(segment
		(start 335.87182 -38.842442)
		(end 336.711036 -38.003226)
		(width 0.127)
		(layer "In4.Cu")
		(net "FM_TPM_PRSNT_N")
	)
	(segment
		(start 306.215542 -38.375844)
		(end 309.29199 -35.299396)
		(width 0.127)
		(layer "In4.Cu")
		(net "FM_TPM_PRSNT_N")
	)
	(segment
		(start 322.67271 -39.101014)
		(end 327.482454 -39.101014)
		(width 0.127)
		(layer "In4.Cu")
		(net "FM_TPM_PRSNT_N")
	)
	(segment
		(start 174.095664 -57.409588)
		(end 171.123102 -60.38215)
		(width 0.127)
		(layer "In11.Cu")
		(net "FM_TPM_PRSNT_N")
	)
	(segment
		(start 236.339888 -62.507622)
		(end 236.339888 -63.068708)
		(width 0.127)
		(layer "In11.Cu")
		(net "FM_TPM_PRSNT_N")
	)
	(segment
		(start 235.364782 -64.043814)
		(end 198.101712 -64.043814)
		(width 0.127)
		(layer "In11.Cu")
		(net "FM_TPM_PRSNT_N")
	)
	(segment
		(start 191.467486 -57.409588)
		(end 174.095664 -57.409588)
		(width 0.127)
		(layer "In11.Cu")
		(net "FM_TPM_PRSNT_N")
	)
	(segment
		(start 236.339888 -63.068708)
		(end 235.364782 -64.043814)
		(width 0.127)
		(layer "In11.Cu")
		(net "FM_TPM_PRSNT_N")
	)
	(segment
		(start 198.101712 -64.043814)
		(end 191.467486 -57.409588)
		(width 0.127)
		(layer "In11.Cu")
		(net "FM_TPM_PRSNT_N")
	)
	(segment
		(start 163.024312 -107.403392)
		(end 163.63188 -108.01096)
		(width 0.127)
		(layer "In13.Cu")
		(net "FM_TPM_PRSNT_N")
	)
	(segment
		(start 163.63188 -108.01096)
		(end 163.63188 -108.295948)
		(width 0.127)
		(layer "In13.Cu")
		(net "FM_TPM_PRSNT_N")
	)
	(segment
		(start 163.32581 -106.487976)
		(end 163.024312 -106.789474)
		(width 0.127)
		(layer "In13.Cu")
		(net "FM_TPM_PRSNT_N")
	)
	(segment
		(start 163.024312 -106.789474)
		(end 163.024312 -107.403392)
		(width 0.127)
		(layer "In13.Cu")
		(net "FM_TPM_PRSNT_N")
	)
	(segment
		(start 161.15792 -101.456998)
		(end 161.15792 -102.474522)
		(width 0.127)
		(layer "In13.Cu")
		(net "FM_TPM_PRSNT_N")
	)
	(segment
		(start 162.428682 -89.808558)
		(end 162.428682 -100.186236)
		(width 0.127)
		(layer "In13.Cu")
		(net "FM_TPM_PRSNT_N")
	)
	(segment
		(start 163.32581 -105.30332)
		(end 163.32581 -106.487976)
		(width 0.127)
		(layer "In13.Cu")
		(net "FM_TPM_PRSNT_N")
	)
	(segment
		(start 162.733482 -104.710992)
		(end 163.32581 -105.30332)
		(width 0.127)
		(layer "In13.Cu")
		(net "FM_TPM_PRSNT_N")
	)
	(segment
		(start 162.428682 -100.186236)
		(end 161.15792 -101.456998)
		(width 0.127)
		(layer "In13.Cu")
		(net "FM_TPM_PRSNT_N")
	)
	(segment
		(start 161.15792 -102.474522)
		(end 162.733482 -104.050084)
		(width 0.127)
		(layer "In13.Cu")
		(net "FM_TPM_PRSNT_N")
	)
	(segment
		(start 170.983148 -60.522104)
		(end 170.983148 -81.254092)
		(width 0.127)
		(layer "In13.Cu")
		(net "FM_TPM_PRSNT_N")
	)
	(segment
		(start 171.123102 -60.38215)
		(end 170.983148 -60.522104)
		(width 0.127)
		(layer "In13.Cu")
		(net "FM_TPM_PRSNT_N")
	)
	(segment
		(start 170.983148 -81.254092)
		(end 162.428682 -89.808558)
		(width 0.127)
		(layer "In13.Cu")
		(net "FM_TPM_PRSNT_N")
	)
	(segment
		(start 162.733482 -104.050084)
		(end 162.733482 -104.710992)
		(width 0.127)
		(layer "In13.Cu")
		(net "FM_TPM_PRSNT_N")
	)
	(segment
		(start 308.803802 -29.048202)
		(end 307.996336 -29.855668)
		(width 0.12954)
		(layer "F.Cu")
		(net "FM_THROTTLE_R_N")
	)
	(segment
		(start 185.355738 -116.175536)
		(end 185.755788 -116.575586)
		(width 0.12954)
		(layer "F.Cu")
		(net "FM_THROTTLE_R_N")
	)
	(segment
		(start 307.996336 -29.855668)
		(end 307.899308 -29.855668)
		(width 0.12954)
		(layer "F.Cu")
		(net "FM_THROTTLE_R_N")
	)
	(via
		(at 308.803802 -29.048202)
		(size 0.508)
		(drill 0.254)
		(layers "F.Cu" "B.Cu")
		(net "FM_THROTTLE_R_N")
	)
	(via
		(at 322.38188 -121.249948)
		(size 0.508)
		(drill 0.254)
		(layers "F.Cu" "B.Cu")
		(net "FM_THROTTLE_R_N")
	)
	(via
		(at 185.755788 -116.575586)
		(size 0.4572)
		(drill 0.254)
		(layers "F.Cu" "B.Cu")
		(net "FM_THROTTLE_R_N")
	)
	(segment
		(start 322.88988 -120.741948)
		(end 322.38188 -121.249948)
		(width 0.127)
		(layer "In2.Cu")
		(net "FM_THROTTLE_R_N")
	)
	(segment
		(start 308.565296 -29.286708)
		(end 308.565296 -34.426652)
		(width 0.127)
		(layer "In2.Cu")
		(net "FM_THROTTLE_R_N")
	)
	(segment
		(start 309.699152 -42.406316)
		(end 309.699152 -52.484528)
		(width 0.127)
		(layer "In2.Cu")
		(net "FM_THROTTLE_R_N")
	)
	(segment
		(start 309.699152 -52.484528)
		(end 308.78018 -53.4035)
		(width 0.127)
		(layer "In2.Cu")
		(net "FM_THROTTLE_R_N")
	)
	(segment
		(start 307.665374 -35.326574)
		(end 307.665374 -40.372538)
		(width 0.127)
		(layer "In2.Cu")
		(net "FM_THROTTLE_R_N")
	)
	(segment
		(start 322.38188 -80.536796)
		(end 322.38188 -111.851948)
		(width 0.127)
		(layer "In2.Cu")
		(net "FM_THROTTLE_R_N")
	)
	(segment
		(start 308.78018 -54.688232)
		(end 312.40222 -58.310272)
		(width 0.127)
		(layer "In2.Cu")
		(net "FM_THROTTLE_R_N")
	)
	(segment
		(start 312.40222 -58.310272)
		(end 312.40222 -66.425826)
		(width 0.127)
		(layer "In2.Cu")
		(net "FM_THROTTLE_R_N")
	)
	(segment
		(start 315.323474 -73.47839)
		(end 322.38188 -80.536796)
		(width 0.127)
		(layer "In2.Cu")
		(net "FM_THROTTLE_R_N")
	)
	(segment
		(start 322.38188 -111.851948)
		(end 322.88988 -112.359948)
		(width 0.127)
		(layer "In2.Cu")
		(net "FM_THROTTLE_R_N")
	)
	(segment
		(start 312.40222 -66.425826)
		(end 315.323474 -73.47839)
		(width 0.127)
		(layer "In2.Cu")
		(net "FM_THROTTLE_R_N")
	)
	(segment
		(start 308.803802 -29.048202)
		(end 308.565296 -29.286708)
		(width 0.127)
		(layer "In2.Cu")
		(net "FM_THROTTLE_R_N")
	)
	(segment
		(start 307.665374 -40.372538)
		(end 309.699152 -42.406316)
		(width 0.127)
		(layer "In2.Cu")
		(net "FM_THROTTLE_R_N")
	)
	(segment
		(start 308.565296 -34.426652)
		(end 307.665374 -35.326574)
		(width 0.127)
		(layer "In2.Cu")
		(net "FM_THROTTLE_R_N")
	)
	(segment
		(start 308.78018 -53.4035)
		(end 308.78018 -54.688232)
		(width 0.127)
		(layer "In2.Cu")
		(net "FM_THROTTLE_R_N")
	)
	(segment
		(start 322.88988 -112.359948)
		(end 322.88988 -120.741948)
		(width 0.127)
		(layer "In2.Cu")
		(net "FM_THROTTLE_R_N")
	)
	(segment
		(start 186.41695 -117.075204)
		(end 185.917332 -116.575586)
		(width 0.127)
		(layer "In15.Cu")
		(net "FM_THROTTLE_R_N")
	)
	(segment
		(start 198.807832 -123.510548)
		(end 194.426586 -123.510548)
		(width 0.127)
		(layer "In15.Cu")
		(net "FM_THROTTLE_R_N")
	)
	(segment
		(start 220.870272 -118.600728)
		(end 216.453212 -123.017788)
		(width 0.127)
		(layer "In15.Cu")
		(net "FM_THROTTLE_R_N")
	)
	(segment
		(start 249.7709 -122.354848)
		(end 247.8024 -124.323348)
		(width 0.127)
		(layer "In15.Cu")
		(net "FM_THROTTLE_R_N")
	)
	(segment
		(start 192.480438 -121.1072)
		(end 191.922146 -121.1072)
		(width 0.127)
		(layer "In15.Cu")
		(net "FM_THROTTLE_R_N")
	)
	(segment
		(start 188.031374 -117.743986)
		(end 186.41695 -117.075204)
		(width 0.127)
		(layer "In15.Cu")
		(net "FM_THROTTLE_R_N")
	)
	(segment
		(start 188.558932 -117.743986)
		(end 188.031374 -117.743986)
		(width 0.127)
		(layer "In15.Cu")
		(net "FM_THROTTLE_R_N")
	)
	(segment
		(start 247.8024 -124.323348)
		(end 245.721124 -124.323348)
		(width 0.127)
		(layer "In15.Cu")
		(net "FM_THROTTLE_R_N")
	)
	(segment
		(start 193.938144 -123.022106)
		(end 193.938144 -122.564906)
		(width 0.127)
		(layer "In15.Cu")
		(net "FM_THROTTLE_R_N")
	)
	(segment
		(start 199.392032 -124.094748)
		(end 198.807832 -123.510548)
		(width 0.127)
		(layer "In15.Cu")
		(net "FM_THROTTLE_R_N")
	)
	(segment
		(start 321.01028 -119.878348)
		(end 284.465268 -119.878348)
		(width 0.127)
		(layer "In15.Cu")
		(net "FM_THROTTLE_R_N")
	)
	(segment
		(start 194.426586 -123.510548)
		(end 193.938144 -123.022106)
		(width 0.127)
		(layer "In15.Cu")
		(net "FM_THROTTLE_R_N")
	)
	(segment
		(start 185.917332 -116.575586)
		(end 185.755788 -116.575586)
		(width 0.127)
		(layer "In15.Cu")
		(net "FM_THROTTLE_R_N")
	)
	(segment
		(start 281.988768 -122.354848)
		(end 249.7709 -122.354848)
		(width 0.127)
		(layer "In15.Cu")
		(net "FM_THROTTLE_R_N")
	)
	(segment
		(start 284.465268 -119.878348)
		(end 281.988768 -122.354848)
		(width 0.127)
		(layer "In15.Cu")
		(net "FM_THROTTLE_R_N")
	)
	(segment
		(start 216.453212 -123.017788)
		(end 208.1022 -123.017788)
		(width 0.127)
		(layer "In15.Cu")
		(net "FM_THROTTLE_R_N")
	)
	(segment
		(start 245.721124 -124.323348)
		(end 242.787424 -121.389648)
		(width 0.127)
		(layer "In15.Cu")
		(net "FM_THROTTLE_R_N")
	)
	(segment
		(start 208.1022 -123.017788)
		(end 207.02524 -124.094748)
		(width 0.127)
		(layer "In15.Cu")
		(net "FM_THROTTLE_R_N")
	)
	(segment
		(start 231.928924 -118.600728)
		(end 220.870272 -118.600728)
		(width 0.127)
		(layer "In15.Cu")
		(net "FM_THROTTLE_R_N")
	)
	(segment
		(start 242.787424 -121.389648)
		(end 234.717844 -121.389648)
		(width 0.127)
		(layer "In15.Cu")
		(net "FM_THROTTLE_R_N")
	)
	(segment
		(start 193.938144 -122.564906)
		(end 192.480438 -121.1072)
		(width 0.127)
		(layer "In15.Cu")
		(net "FM_THROTTLE_R_N")
	)
	(segment
		(start 322.38188 -121.249948)
		(end 321.01028 -119.878348)
		(width 0.127)
		(layer "In15.Cu")
		(net "FM_THROTTLE_R_N")
	)
	(segment
		(start 207.02524 -124.094748)
		(end 199.392032 -124.094748)
		(width 0.127)
		(layer "In15.Cu")
		(net "FM_THROTTLE_R_N")
	)
	(segment
		(start 191.922146 -121.1072)
		(end 188.558932 -117.743986)
		(width 0.127)
		(layer "In15.Cu")
		(net "FM_THROTTLE_R_N")
	)
	(segment
		(start 234.717844 -121.389648)
		(end 231.928924 -118.600728)
		(width 0.127)
		(layer "In15.Cu")
		(net "FM_THROTTLE_R_N")
	)
	(segment
		(start 321.819778 -37.930328)
		(end 322.316602 -37.930328)
		(width 0.12954)
		(layer "F.Cu")
		(net "FM_THROTTLE_N")
	)
	(segment
		(start 322.316602 -37.930328)
		(end 323.662802 -39.276528)
		(width 0.12954)
		(layer "F.Cu")
		(net "FM_THROTTLE_N")
	)
	(segment
		(start 315.586364 -32.850074)
		(end 316.855348 -33.697926)
		(width 0.12954)
		(layer "F.Cu")
		(net "FM_THROTTLE_N")
	)
	(segment
		(start 308.211728 -30.343348)
		(end 309.122572 -30.343348)
		(width 0.12954)
		(layer "F.Cu")
		(net "FM_THROTTLE_N")
	)
	(segment
		(start 309.252112 -31.011368)
		(end 310.170576 -31.011368)
		(width 0.12954)
		(layer "F.Cu")
		(net "FM_THROTTLE_N")
	)
	(segment
		(start 309.122572 -30.881828)
		(end 309.252112 -31.011368)
		(width 0.12954)
		(layer "F.Cu")
		(net "FM_THROTTLE_N")
	)
	(segment
		(start 318.69126 -35.533838)
		(end 319.423288 -35.533838)
		(width 0.12954)
		(layer "F.Cu")
		(net "FM_THROTTLE_N")
	)
	(segment
		(start 319.423288 -35.533838)
		(end 321.819778 -37.930328)
		(width 0.12954)
		(layer "F.Cu")
		(net "FM_THROTTLE_N")
	)
	(segment
		(start 313.751214 -31.700216)
		(end 315.28512 -32.72536)
		(width 0.12954)
		(layer "F.Cu")
		(net "FM_THROTTLE_N")
	)
	(segment
		(start 307.899308 -30.655768)
		(end 308.211728 -30.343348)
		(width 0.12954)
		(layer "F.Cu")
		(net "FM_THROTTLE_N")
	)
	(segment
		(start 310.170576 -31.011368)
		(end 310.711596 -30.470348)
		(width 0.12954)
		(layer "F.Cu")
		(net "FM_THROTTLE_N")
	)
	(segment
		(start 323.662802 -39.276528)
		(end 325.833232 -41.446958)
		(width 0.0889)
		(layer "F.Cu")
		(net "FM_THROTTLE_N")
	)
	(segment
		(start 315.28512 -32.72536)
		(end 315.586364 -32.850074)
		(width 0.12954)
		(layer "F.Cu")
		(net "FM_THROTTLE_N")
	)
	(segment
		(start 309.122572 -30.343348)
		(end 309.122572 -30.881828)
		(width 0.12954)
		(layer "F.Cu")
		(net "FM_THROTTLE_N")
	)
	(segment
		(start 312.521346 -30.470348)
		(end 313.751214 -31.700216)
		(width 0.12954)
		(layer "F.Cu")
		(net "FM_THROTTLE_N")
	)
	(segment
		(start 316.855348 -33.697926)
		(end 318.69126 -35.533838)
		(width 0.12954)
		(layer "F.Cu")
		(net "FM_THROTTLE_N")
	)
	(segment
		(start 311.676796 -30.470348)
		(end 312.521346 -30.470348)
		(width 0.12954)
		(layer "F.Cu")
		(net "FM_THROTTLE_N")
	)
	(segment
		(start 325.833232 -41.446958)
		(end 326.999854 -41.446958)
		(width 0.0889)
		(layer "F.Cu")
		(net "FM_THROTTLE_N")
	)
	(segment
		(start 310.711596 -30.470348)
		(end 311.676796 -30.470348)
		(width 0.12954)
		(layer "F.Cu")
		(net "FM_THROTTLE_N")
	)
	(via
		(at 311.676796 -30.470348)
		(size 0.762)
		(drill 0.381)
		(layers "F.Cu" "B.Cu")
		(net "FM_THROTTLE_N")
	)
	(segment
		(start 184.555638 -106.575352)
		(end 184.955688 -106.175302)
		(width 0.12954)
		(layer "F.Cu")
		(net "FM_THERMTRIP_DLY_LVC1_R_N")
	)
	(segment
		(start 188.0108 -94.3102)
		(end 188.0108 -95.2754)
		(width 0.12954)
		(layer "F.Cu")
		(net "FM_THERMTRIP_DLY_LVC1_R_N")
	)
	(via
		(at 188.0108 -95.2754)
		(size 0.508)
		(drill 0.254)
		(layers "F.Cu" "B.Cu")
		(net "FM_THERMTRIP_DLY_LVC1_R_N")
	)
	(via
		(at 184.955688 -106.175302)
		(size 0.4572)
		(drill 0.254)
		(layers "F.Cu" "B.Cu")
		(net "FM_THERMTRIP_DLY_LVC1_R_N")
	)
	(segment
		(start 184.955688 -99.67976)
		(end 185.58002 -99.055428)
		(width 0.127)
		(layer "In2.Cu")
		(net "FM_THERMTRIP_DLY_LVC1_R_N")
	)
	(segment
		(start 184.955688 -106.175302)
		(end 184.955688 -99.67976)
		(width 0.127)
		(layer "In2.Cu")
		(net "FM_THERMTRIP_DLY_LVC1_R_N")
	)
	(segment
		(start 185.58002 -99.055428)
		(end 185.58002 -97.2566)
		(width 0.127)
		(layer "In2.Cu")
		(net "FM_THERMTRIP_DLY_LVC1_R_N")
	)
	(segment
		(start 186.59602 -96.2406)
		(end 187.4266 -96.2406)
		(width 0.127)
		(layer "In2.Cu")
		(net "FM_THERMTRIP_DLY_LVC1_R_N")
	)
	(segment
		(start 188.0108 -95.6564)
		(end 188.0108 -95.2754)
		(width 0.127)
		(layer "In2.Cu")
		(net "FM_THERMTRIP_DLY_LVC1_R_N")
	)
	(segment
		(start 185.58002 -97.2566)
		(end 186.59602 -96.2406)
		(width 0.127)
		(layer "In2.Cu")
		(net "FM_THERMTRIP_DLY_LVC1_R_N")
	)
	(segment
		(start 187.4266 -96.2406)
		(end 188.0108 -95.6564)
		(width 0.127)
		(layer "In2.Cu")
		(net "FM_THERMTRIP_DLY_LVC1_R_N")
	)
	(segment
		(start 319.139316 -64.038988)
		(end 319.699132 -64.038988)
		(width 0.12954)
		(layer "F.Cu")
		(net "FM_THERMTRIP_DLY_LVC1_N")
	)
	(segment
		(start 188.4172 -92.6846)
		(end 188.0108 -93.091)
		(width 0.12954)
		(layer "F.Cu")
		(net "FM_THERMTRIP_DLY_LVC1_N")
	)
	(segment
		(start 188.4172 -92.2528)
		(end 188.4172 -92.6846)
		(width 0.12954)
		(layer "F.Cu")
		(net "FM_THERMTRIP_DLY_LVC1_N")
	)
	(segment
		(start 188.0108 -93.091)
		(end 188.0108 -93.5101)
		(width 0.12954)
		(layer "F.Cu")
		(net "FM_THERMTRIP_DLY_LVC1_N")
	)
	(segment
		(start 319.699132 -64.038988)
		(end 319.841372 -63.896748)
		(width 0.12954)
		(layer "F.Cu")
		(net "FM_THERMTRIP_DLY_LVC1_N")
	)
	(via
		(at 188.4172 -92.2528)
		(size 0.508)
		(drill 0.254)
		(layers "F.Cu" "B.Cu")
		(net "FM_THERMTRIP_DLY_LVC1_N")
	)
	(via
		(at 319.139316 -64.038988)
		(size 0.508)
		(drill 0.254)
		(layers "F.Cu" "B.Cu")
		(net "FM_THERMTRIP_DLY_LVC1_N")
	)
	(segment
		(start 212.898482 -90.391996)
		(end 210.631278 -92.6592)
		(width 0.127)
		(layer "In11.Cu")
		(net "FM_THERMTRIP_DLY_LVC1_N")
	)
	(segment
		(start 304.93208 -66.814446)
		(end 304.93208 -76.625958)
		(width 0.127)
		(layer "In11.Cu")
		(net "FM_THERMTRIP_DLY_LVC1_N")
	)
	(segment
		(start 232.628186 -73.370948)
		(end 215.607138 -90.391996)
		(width 0.127)
		(layer "In11.Cu")
		(net "FM_THERMTRIP_DLY_LVC1_N")
	)
	(segment
		(start 195.326 -93.1418)
		(end 194.8434 -92.6592)
		(width 0.127)
		(layer "In11.Cu")
		(net "FM_THERMTRIP_DLY_LVC1_N")
	)
	(segment
		(start 305.360578 -66.385948)
		(end 304.93208 -66.814446)
		(width 0.127)
		(layer "In11.Cu")
		(net "FM_THERMTRIP_DLY_LVC1_N")
	)
	(segment
		(start 239.796574 -73.370948)
		(end 232.628186 -73.370948)
		(width 0.127)
		(layer "In11.Cu")
		(net "FM_THERMTRIP_DLY_LVC1_N")
	)
	(segment
		(start 215.607138 -90.391996)
		(end 212.898482 -90.391996)
		(width 0.127)
		(layer "In11.Cu")
		(net "FM_THERMTRIP_DLY_LVC1_N")
	)
	(segment
		(start 249.56516 -83.139534)
		(end 239.796574 -73.370948)
		(width 0.127)
		(layer "In11.Cu")
		(net "FM_THERMTRIP_DLY_LVC1_N")
	)
	(segment
		(start 304.93208 -76.625958)
		(end 298.418504 -83.139534)
		(width 0.127)
		(layer "In11.Cu")
		(net "FM_THERMTRIP_DLY_LVC1_N")
	)
	(segment
		(start 313.99988 -66.385948)
		(end 305.360578 -66.385948)
		(width 0.127)
		(layer "In11.Cu")
		(net "FM_THERMTRIP_DLY_LVC1_N")
	)
	(segment
		(start 194.8434 -92.6592)
		(end 191.135 -92.6592)
		(width 0.127)
		(layer "In11.Cu")
		(net "FM_THERMTRIP_DLY_LVC1_N")
	)
	(segment
		(start 206.7306 -93.1418)
		(end 195.326 -93.1418)
		(width 0.127)
		(layer "In11.Cu")
		(net "FM_THERMTRIP_DLY_LVC1_N")
	)
	(segment
		(start 210.631278 -92.6592)
		(end 207.2132 -92.6592)
		(width 0.127)
		(layer "In11.Cu")
		(net "FM_THERMTRIP_DLY_LVC1_N")
	)
	(segment
		(start 319.139316 -64.038988)
		(end 316.34684 -64.038988)
		(width 0.127)
		(layer "In11.Cu")
		(net "FM_THERMTRIP_DLY_LVC1_N")
	)
	(segment
		(start 191.135 -92.6592)
		(end 190.7286 -92.2528)
		(width 0.127)
		(layer "In11.Cu")
		(net "FM_THERMTRIP_DLY_LVC1_N")
	)
	(segment
		(start 207.2132 -92.6592)
		(end 206.7306 -93.1418)
		(width 0.127)
		(layer "In11.Cu")
		(net "FM_THERMTRIP_DLY_LVC1_N")
	)
	(segment
		(start 190.7286 -92.2528)
		(end 188.4172 -92.2528)
		(width 0.127)
		(layer "In11.Cu")
		(net "FM_THERMTRIP_DLY_LVC1_N")
	)
	(segment
		(start 316.34684 -64.038988)
		(end 313.99988 -66.385948)
		(width 0.127)
		(layer "In11.Cu")
		(net "FM_THERMTRIP_DLY_LVC1_N")
	)
	(segment
		(start 298.418504 -83.139534)
		(end 249.56516 -83.139534)
		(width 0.127)
		(layer "In11.Cu")
		(net "FM_THERMTRIP_DLY_LVC1_N")
	)
	(segment
		(start 186.155584 -115.375436)
		(end 186.571636 -115.791488)
		(width 0.12954)
		(layer "F.Cu")
		(net "FM_SYS_THROTTLE_R_N")
	)
	(segment
		(start 190.57366 -117.389148)
		(end 190.75908 -117.389148)
		(width 0.12954)
		(layer "F.Cu")
		(net "FM_SYS_THROTTLE_R_N")
	)
	(segment
		(start 192.71488 -119.344948)
		(end 192.98031 -119.344948)
		(width 0.12954)
		(layer "F.Cu")
		(net "FM_SYS_THROTTLE_R_N")
	)
	(segment
		(start 389.51408 -28.108148)
		(end 390.056878 -27.56535)
		(width 0.12954)
		(layer "F.Cu")
		(net "FM_SYS_THROTTLE_R_N")
	)
	(segment
		(start 113.44656 -27.367738)
		(end 113.44656 -26.556208)
		(width 0.12954)
		(layer "F.Cu")
		(net "FM_SYS_THROTTLE_R_N")
	)
	(segment
		(start 390.056878 -27.56535)
		(end 390.056878 -27.109928)
		(width 0.12954)
		(layer "F.Cu")
		(net "FM_SYS_THROTTLE_R_N")
	)
	(segment
		(start 190.57366 -117.150388)
		(end 190.57366 -117.389148)
		(width 0.12954)
		(layer "F.Cu")
		(net "FM_SYS_THROTTLE_R_N")
	)
	(segment
		(start 190.75908 -117.389148)
		(end 192.71488 -119.344948)
		(width 0.12954)
		(layer "F.Cu")
		(net "FM_SYS_THROTTLE_R_N")
	)
	(segment
		(start 186.571636 -115.791488)
		(end 189.21476 -115.791488)
		(width 0.12954)
		(layer "F.Cu")
		(net "FM_SYS_THROTTLE_R_N")
	)
	(segment
		(start 189.21476 -115.791488)
		(end 190.57366 -117.150388)
		(width 0.12954)
		(layer "F.Cu")
		(net "FM_SYS_THROTTLE_R_N")
	)
	(via
		(at 190.57366 -117.389148)
		(size 0.508)
		(drill 0.254)
		(layers "F.Cu" "B.Cu")
		(net "FM_SYS_THROTTLE_R_N")
	)
	(via
		(at 113.44656 -26.556208)
		(size 0.508)
		(drill 0.254)
		(layers "F.Cu" "B.Cu")
		(net "FM_SYS_THROTTLE_R_N")
	)
	(via
		(at 389.51408 -28.108148)
		(size 0.508)
		(drill 0.254)
		(layers "F.Cu" "B.Cu")
		(net "FM_SYS_THROTTLE_R_N")
	)
	(via
		(at 137.27684 -50.899568)
		(size 0.508)
		(drill 0.254)
		(layers "F.Cu" "B.Cu")
		(net "FM_SYS_THROTTLE_R_N")
	)
	(segment
		(start 188.69025 -95.9612)
		(end 189.12078 -96.39173)
		(width 0.127)
		(layer "In4.Cu")
		(net "FM_SYS_THROTTLE_R_N")
	)
	(segment
		(start 142.47114 -71.506588)
		(end 161.148268 -71.506588)
		(width 0.127)
		(layer "In4.Cu")
		(net "FM_SYS_THROTTLE_R_N")
	)
	(segment
		(start 137.27684 -50.899568)
		(end 137.19556 -50.980848)
		(width 0.127)
		(layer "In4.Cu")
		(net "FM_SYS_THROTTLE_R_N")
	)
	(segment
		(start 187.4266 -95.6564)
		(end 187.7314 -95.9612)
		(width 0.127)
		(layer "In4.Cu")
		(net "FM_SYS_THROTTLE_R_N")
	)
	(segment
		(start 190.348616 -117.164104)
		(end 190.57366 -117.389148)
		(width 0.127)
		(layer "In4.Cu")
		(net "FM_SYS_THROTTLE_R_N")
	)
	(segment
		(start 190.348616 -97.58553)
		(end 190.348616 -117.164104)
		(width 0.127)
		(layer "In4.Cu")
		(net "FM_SYS_THROTTLE_R_N")
	)
	(segment
		(start 187.7314 -95.9612)
		(end 188.69025 -95.9612)
		(width 0.127)
		(layer "In4.Cu")
		(net "FM_SYS_THROTTLE_R_N")
	)
	(segment
		(start 189.12078 -96.39173)
		(end 189.12078 -96.76638)
		(width 0.127)
		(layer "In4.Cu")
		(net "FM_SYS_THROTTLE_R_N")
	)
	(segment
		(start 189.664848 -97.310448)
		(end 190.073534 -97.310448)
		(width 0.127)
		(layer "In4.Cu")
		(net "FM_SYS_THROTTLE_R_N")
	)
	(segment
		(start 187.4266 -87.6554)
		(end 187.4266 -95.6564)
		(width 0.127)
		(layer "In4.Cu")
		(net "FM_SYS_THROTTLE_R_N")
	)
	(segment
		(start 161.148268 -71.506588)
		(end 176.41697 -86.77529)
		(width 0.127)
		(layer "In4.Cu")
		(net "FM_SYS_THROTTLE_R_N")
	)
	(segment
		(start 137.19556 -50.980848)
		(end 137.19556 -66.231008)
		(width 0.127)
		(layer "In4.Cu")
		(net "FM_SYS_THROTTLE_R_N")
	)
	(segment
		(start 190.073534 -97.310448)
		(end 190.348616 -97.58553)
		(width 0.127)
		(layer "In4.Cu")
		(net "FM_SYS_THROTTLE_R_N")
	)
	(segment
		(start 186.54649 -86.77529)
		(end 187.4266 -87.6554)
		(width 0.127)
		(layer "In4.Cu")
		(net "FM_SYS_THROTTLE_R_N")
	)
	(segment
		(start 176.41697 -86.77529)
		(end 186.54649 -86.77529)
		(width 0.127)
		(layer "In4.Cu")
		(net "FM_SYS_THROTTLE_R_N")
	)
	(segment
		(start 189.12078 -96.76638)
		(end 189.664848 -97.310448)
		(width 0.127)
		(layer "In4.Cu")
		(net "FM_SYS_THROTTLE_R_N")
	)
	(segment
		(start 137.19556 -66.231008)
		(end 142.47114 -71.506588)
		(width 0.127)
		(layer "In4.Cu")
		(net "FM_SYS_THROTTLE_R_N")
	)
	(segment
		(start 136.778492 -13.509244)
		(end 138.040872 -14.771624)
		(width 0.127)
		(layer "In11.Cu")
		(net "FM_SYS_THROTTLE_R_N")
	)
	(segment
		(start 258.453382 -40.143684)
		(end 263.686798 -34.910268)
		(width 0.127)
		(layer "In11.Cu")
		(net "FM_SYS_THROTTLE_R_N")
	)
	(segment
		(start 163.134802 -21.186648)
		(end 167.337994 -21.186648)
		(width 0.127)
		(layer "In11.Cu")
		(net "FM_SYS_THROTTLE_R_N")
	)
	(segment
		(start 109.79404 -15.78102)
		(end 112.065816 -13.509244)
		(width 0.127)
		(layer "In11.Cu")
		(net "FM_SYS_THROTTLE_R_N")
	)
	(segment
		(start 112.065816 -13.509244)
		(end 136.778492 -13.509244)
		(width 0.127)
		(layer "In11.Cu")
		(net "FM_SYS_THROTTLE_R_N")
	)
	(segment
		(start 298.129198 -24.85263)
		(end 305.481736 -17.500092)
		(width 0.127)
		(layer "In11.Cu")
		(net "FM_SYS_THROTTLE_R_N")
	)
	(segment
		(start 119.26824 -34.722308)
		(end 119.26824 -44.940728)
		(width 0.127)
		(layer "In11.Cu")
		(net "FM_SYS_THROTTLE_R_N")
	)
	(segment
		(start 258.453382 -41.159684)
		(end 258.453382 -40.143684)
		(width 0.127)
		(layer "In11.Cu")
		(net "FM_SYS_THROTTLE_R_N")
	)
	(segment
		(start 109.79404 -22.903688)
		(end 109.79404 -15.78102)
		(width 0.127)
		(layer "In11.Cu")
		(net "FM_SYS_THROTTLE_R_N")
	)
	(segment
		(start 201.068686 -28.638754)
		(end 204.495146 -32.065214)
		(width 0.127)
		(layer "In11.Cu")
		(net "FM_SYS_THROTTLE_R_N")
	)
	(segment
		(start 239.36833 -47.482252)
		(end 240.365534 -46.485048)
		(width 0.127)
		(layer "In11.Cu")
		(net "FM_SYS_THROTTLE_R_N")
	)
	(segment
		(start 248.217944 -41.743122)
		(end 253.022354 -41.743122)
		(width 0.127)
		(layer "In11.Cu")
		(net "FM_SYS_THROTTLE_R_N")
	)
	(segment
		(start 322.301362 -16.646398)
		(end 361.47121 -16.646398)
		(width 0.127)
		(layer "In11.Cu")
		(net "FM_SYS_THROTTLE_R_N")
	)
	(segment
		(start 113.44656 -28.900628)
		(end 119.26824 -34.722308)
		(width 0.127)
		(layer "In11.Cu")
		(net "FM_SYS_THROTTLE_R_N")
	)
	(segment
		(start 195.86448 -25.182576)
		(end 199.320658 -28.638754)
		(width 0.127)
		(layer "In11.Cu")
		(net "FM_SYS_THROTTLE_R_N")
	)
	(segment
		(start 321.447668 -17.500092)
		(end 322.301362 -16.646398)
		(width 0.127)
		(layer "In11.Cu")
		(net "FM_SYS_THROTTLE_R_N")
	)
	(segment
		(start 222.939864 -40.427148)
		(end 223.955864 -41.443148)
		(width 0.127)
		(layer "In11.Cu")
		(net "FM_SYS_THROTTLE_R_N")
	)
	(segment
		(start 204.495146 -32.065214)
		(end 209.879946 -32.065214)
		(width 0.127)
		(layer "In11.Cu")
		(net "FM_SYS_THROTTLE_R_N")
	)
	(segment
		(start 263.686798 -34.910268)
		(end 267.298932 -34.910268)
		(width 0.127)
		(layer "In11.Cu")
		(net "FM_SYS_THROTTLE_R_N")
	)
	(segment
		(start 161.026094 -17.336262)
		(end 161.78022 -18.090388)
		(width 0.127)
		(layer "In11.Cu")
		(net "FM_SYS_THROTTLE_R_N")
	)
	(segment
		(start 253.824994 -42.545762)
		(end 257.067304 -42.545762)
		(width 0.127)
		(layer "In11.Cu")
		(net "FM_SYS_THROTTLE_R_N")
	)
	(segment
		(start 235.76788 -48.605948)
		(end 236.891576 -47.482252)
		(width 0.127)
		(layer "In11.Cu")
		(net "FM_SYS_THROTTLE_R_N")
	)
	(segment
		(start 236.891576 -47.482252)
		(end 239.36833 -47.482252)
		(width 0.127)
		(layer "In11.Cu")
		(net "FM_SYS_THROTTLE_R_N")
	)
	(segment
		(start 167.337994 -21.186648)
		(end 168.71188 -19.812762)
		(width 0.127)
		(layer "In11.Cu")
		(net "FM_SYS_THROTTLE_R_N")
	)
	(segment
		(start 277.35657 -24.85263)
		(end 298.129198 -24.85263)
		(width 0.127)
		(layer "In11.Cu")
		(net "FM_SYS_THROTTLE_R_N")
	)
	(segment
		(start 195.86448 -21.935948)
		(end 195.86448 -25.182576)
		(width 0.127)
		(layer "In11.Cu")
		(net "FM_SYS_THROTTLE_R_N")
	)
	(segment
		(start 361.47121 -16.646398)
		(end 372.93296 -28.108148)
		(width 0.127)
		(layer "In11.Cu")
		(net "FM_SYS_THROTTLE_R_N")
	)
	(segment
		(start 190.804546 -16.876014)
		(end 195.86448 -21.935948)
		(width 0.127)
		(layer "In11.Cu")
		(net "FM_SYS_THROTTLE_R_N")
	)
	(segment
		(start 372.93296 -28.108148)
		(end 389.51408 -28.108148)
		(width 0.127)
		(layer "In11.Cu")
		(net "FM_SYS_THROTTLE_R_N")
	)
	(segment
		(start 243.476018 -46.485048)
		(end 248.217944 -41.743122)
		(width 0.127)
		(layer "In11.Cu")
		(net "FM_SYS_THROTTLE_R_N")
	)
	(segment
		(start 170.805094 -16.876014)
		(end 190.804546 -16.876014)
		(width 0.127)
		(layer "In11.Cu")
		(net "FM_SYS_THROTTLE_R_N")
	)
	(segment
		(start 231.57688 -43.017186)
		(end 231.57688 -47.335948)
		(width 0.127)
		(layer "In11.Cu")
		(net "FM_SYS_THROTTLE_R_N")
	)
	(segment
		(start 113.44656 -26.556208)
		(end 113.44656 -28.900628)
		(width 0.127)
		(layer "In11.Cu")
		(net "FM_SYS_THROTTLE_R_N")
	)
	(segment
		(start 168.71188 -18.969228)
		(end 170.805094 -16.876014)
		(width 0.127)
		(layer "In11.Cu")
		(net "FM_SYS_THROTTLE_R_N")
	)
	(segment
		(start 267.298932 -34.910268)
		(end 277.35657 -24.85263)
		(width 0.127)
		(layer "In11.Cu")
		(net "FM_SYS_THROTTLE_R_N")
	)
	(segment
		(start 161.78022 -19.832066)
		(end 163.134802 -21.186648)
		(width 0.127)
		(layer "In11.Cu")
		(net "FM_SYS_THROTTLE_R_N")
	)
	(segment
		(start 257.067304 -42.545762)
		(end 258.453382 -41.159684)
		(width 0.127)
		(layer "In11.Cu")
		(net "FM_SYS_THROTTLE_R_N")
	)
	(segment
		(start 168.71188 -19.812762)
		(end 168.71188 -18.969228)
		(width 0.127)
		(layer "In11.Cu")
		(net "FM_SYS_THROTTLE_R_N")
	)
	(segment
		(start 199.320658 -28.638754)
		(end 201.068686 -28.638754)
		(width 0.127)
		(layer "In11.Cu")
		(net "FM_SYS_THROTTLE_R_N")
	)
	(segment
		(start 122.41784 -48.090328)
		(end 134.4676 -48.090328)
		(width 0.127)
		(layer "In11.Cu")
		(net "FM_SYS_THROTTLE_R_N")
	)
	(segment
		(start 209.879946 -32.065214)
		(end 218.24188 -40.427148)
		(width 0.127)
		(layer "In11.Cu")
		(net "FM_SYS_THROTTLE_R_N")
	)
	(segment
		(start 149.097746 -14.113256)
		(end 160.038542 -14.113256)
		(width 0.127)
		(layer "In11.Cu")
		(net "FM_SYS_THROTTLE_R_N")
	)
	(segment
		(start 161.026094 -15.100808)
		(end 161.026094 -17.336262)
		(width 0.127)
		(layer "In11.Cu")
		(net "FM_SYS_THROTTLE_R_N")
	)
	(segment
		(start 231.57688 -47.335948)
		(end 232.84688 -48.605948)
		(width 0.127)
		(layer "In11.Cu")
		(net "FM_SYS_THROTTLE_R_N")
	)
	(segment
		(start 218.24188 -40.427148)
		(end 222.939864 -40.427148)
		(width 0.127)
		(layer "In11.Cu")
		(net "FM_SYS_THROTTLE_R_N")
	)
	(segment
		(start 305.481736 -17.500092)
		(end 321.447668 -17.500092)
		(width 0.127)
		(layer "In11.Cu")
		(net "FM_SYS_THROTTLE_R_N")
	)
	(segment
		(start 232.84688 -48.605948)
		(end 235.76788 -48.605948)
		(width 0.127)
		(layer "In11.Cu")
		(net "FM_SYS_THROTTLE_R_N")
	)
	(segment
		(start 160.038542 -14.113256)
		(end 161.026094 -15.100808)
		(width 0.127)
		(layer "In11.Cu")
		(net "FM_SYS_THROTTLE_R_N")
	)
	(segment
		(start 138.040872 -14.771624)
		(end 148.439378 -14.771624)
		(width 0.127)
		(layer "In11.Cu")
		(net "FM_SYS_THROTTLE_R_N")
	)
	(segment
		(start 113.44656 -26.556208)
		(end 109.79404 -22.903688)
		(width 0.127)
		(layer "In11.Cu")
		(net "FM_SYS_THROTTLE_R_N")
	)
	(segment
		(start 253.022354 -41.743122)
		(end 253.824994 -42.545762)
		(width 0.127)
		(layer "In11.Cu")
		(net "FM_SYS_THROTTLE_R_N")
	)
	(segment
		(start 230.002842 -41.443148)
		(end 231.57688 -43.017186)
		(width 0.127)
		(layer "In11.Cu")
		(net "FM_SYS_THROTTLE_R_N")
	)
	(segment
		(start 223.955864 -41.443148)
		(end 230.002842 -41.443148)
		(width 0.127)
		(layer "In11.Cu")
		(net "FM_SYS_THROTTLE_R_N")
	)
	(segment
		(start 148.439378 -14.771624)
		(end 149.097746 -14.113256)
		(width 0.127)
		(layer "In11.Cu")
		(net "FM_SYS_THROTTLE_R_N")
	)
	(segment
		(start 240.365534 -46.485048)
		(end 243.476018 -46.485048)
		(width 0.127)
		(layer "In11.Cu")
		(net "FM_SYS_THROTTLE_R_N")
	)
	(segment
		(start 134.4676 -48.090328)
		(end 137.27684 -50.899568)
		(width 0.127)
		(layer "In11.Cu")
		(net "FM_SYS_THROTTLE_R_N")
	)
	(segment
		(start 161.78022 -18.090388)
		(end 161.78022 -19.832066)
		(width 0.127)
		(layer "In11.Cu")
		(net "FM_SYS_THROTTLE_R_N")
	)
	(segment
		(start 119.26824 -44.940728)
		(end 122.41784 -48.090328)
		(width 0.127)
		(layer "In11.Cu")
		(net "FM_SYS_THROTTLE_R_N")
	)
	(segment
		(start 329.165966 -40.461946)
		(end 328.625708 -40.461946)
		(width 0.12954)
		(layer "F.Cu")
		(net "FM_SUSACK_N")
	)
	(segment
		(start 171.381674 -91.420696)
		(end 169.539666 -91.420696)
		(width 0.12954)
		(layer "F.Cu")
		(net "FM_SUSACK_N")
	)
	(segment
		(start 156.44368 -107.131866)
		(end 156.88183 -107.570016)
		(width 0.12954)
		(layer "F.Cu")
		(net "FM_SUSACK_N")
	)
	(segment
		(start 169.539666 -91.420696)
		(end 168.41978 -92.540582)
		(width 0.12954)
		(layer "F.Cu")
		(net "FM_SUSACK_N")
	)
	(segment
		(start 156.44368 -94.737936)
		(end 156.44368 -107.131866)
		(width 0.12954)
		(layer "F.Cu")
		(net "FM_SUSACK_N")
	)
	(segment
		(start 160.966912 -96.67621)
		(end 158.296356 -94.005654)
		(width 0.12954)
		(layer "F.Cu")
		(net "FM_SUSACK_N")
	)
	(segment
		(start 168.41978 -92.540582)
		(end 168.41978 -94.953074)
		(width 0.12954)
		(layer "F.Cu")
		(net "FM_SUSACK_N")
	)
	(segment
		(start 157.175962 -94.005654)
		(end 156.44368 -94.737936)
		(width 0.12954)
		(layer "F.Cu")
		(net "FM_SUSACK_N")
	)
	(segment
		(start 168.41978 -94.953074)
		(end 166.696644 -96.67621)
		(width 0.12954)
		(layer "F.Cu")
		(net "FM_SUSACK_N")
	)
	(segment
		(start 166.696644 -96.67621)
		(end 160.966912 -96.67621)
		(width 0.12954)
		(layer "F.Cu")
		(net "FM_SUSACK_N")
	)
	(segment
		(start 158.296356 -94.005654)
		(end 157.175962 -94.005654)
		(width 0.12954)
		(layer "F.Cu")
		(net "FM_SUSACK_N")
	)
	(segment
		(start 156.88183 -107.570016)
		(end 156.88183 -108.295948)
		(width 0.12954)
		(layer "F.Cu")
		(net "FM_SUSACK_N")
	)
	(via
		(at 171.381674 -91.420696)
		(size 0.508)
		(drill 0.254)
		(layers "F.Cu" "B.Cu")
		(net "FM_SUSACK_N")
	)
	(via
		(at 163.896802 -59.865006)
		(size 0.508)
		(drill 0.254)
		(layers "F.Cu" "B.Cu")
		(net "FM_SUSACK_N")
	)
	(via
		(at 328.625708 -40.461946)
		(size 0.4572)
		(drill 0.2032)
		(layers "F.Cu" "B.Cu")
		(net "FM_SUSACK_N")
	)
	(via
		(at 289.422078 -57.728358)
		(size 0.508)
		(drill 0.254)
		(layers "F.Cu" "B.Cu")
		(net "FM_SUSACK_N")
	)
	(segment
		(start 328.144886 -33.864296)
		(end 328.144886 -31.311088)
		(width 0.12954)
		(layer "B.Cu")
		(net "FM_SUSACK_N")
	)
	(segment
		(start 328.625708 -39.434008)
		(end 328.51852 -39.32682)
		(width 0.12954)
		(layer "B.Cu")
		(net "FM_SUSACK_N")
	)
	(segment
		(start 327.060814 -30.227524)
		(end 327.060814 -29.24302)
		(width 0.12954)
		(layer "B.Cu")
		(net "FM_SUSACK_N")
	)
	(segment
		(start 328.144886 -31.311088)
		(end 327.060814 -30.227524)
		(width 0.12954)
		(layer "B.Cu")
		(net "FM_SUSACK_N")
	)
	(segment
		(start 327.7362 -35.606482)
		(end 327.4441 -35.314382)
		(width 0.12954)
		(layer "B.Cu")
		(net "FM_SUSACK_N")
	)
	(segment
		(start 327.7362 -37.445188)
		(end 327.7362 -35.606482)
		(width 0.12954)
		(layer "B.Cu")
		(net "FM_SUSACK_N")
	)
	(segment
		(start 328.51852 -38.227508)
		(end 327.7362 -37.445188)
		(width 0.12954)
		(layer "B.Cu")
		(net "FM_SUSACK_N")
	)
	(segment
		(start 327.4441 -35.314382)
		(end 327.4441 -34.565082)
		(width 0.12954)
		(layer "B.Cu")
		(net "FM_SUSACK_N")
	)
	(segment
		(start 328.625708 -40.461946)
		(end 328.625708 -39.434008)
		(width 0.12954)
		(layer "B.Cu")
		(net "FM_SUSACK_N")
	)
	(segment
		(start 328.51852 -39.32682)
		(end 328.51852 -38.227508)
		(width 0.12954)
		(layer "B.Cu")
		(net "FM_SUSACK_N")
	)
	(segment
		(start 327.4441 -34.565082)
		(end 328.144886 -33.864296)
		(width 0.12954)
		(layer "B.Cu")
		(net "FM_SUSACK_N")
	)
	(segment
		(start 164.585904 -84.624926)
		(end 164.585904 -61.868558)
		(width 0.127)
		(layer "In2.Cu")
		(net "FM_SUSACK_N")
	)
	(segment
		(start 164.585904 -61.868558)
		(end 163.896802 -61.179456)
		(width 0.127)
		(layer "In2.Cu")
		(net "FM_SUSACK_N")
	)
	(segment
		(start 171.381674 -91.420696)
		(end 164.585904 -84.624926)
		(width 0.127)
		(layer "In2.Cu")
		(net "FM_SUSACK_N")
	)
	(segment
		(start 163.896802 -61.179456)
		(end 163.896802 -59.865006)
		(width 0.127)
		(layer "In2.Cu")
		(net "FM_SUSACK_N")
	)
	(segment
		(start 195.2371 -80.457548)
		(end 192.93205 -78.152498)
		(width 0.127)
		(layer "In6.Cu")
		(net "FM_SUSACK_N")
	)
	(segment
		(start 283.829252 -74.641202)
		(end 276.145752 -82.324702)
		(width 0.127)
		(layer "In6.Cu")
		(net "FM_SUSACK_N")
	)
	(segment
		(start 289.422078 -57.728358)
		(end 289.422078 -59.1947)
		(width 0.127)
		(layer "In6.Cu")
		(net "FM_SUSACK_N")
	)
	(segment
		(start 239.220756 -87.50046)
		(end 213.228682 -87.50046)
		(width 0.127)
		(layer "In6.Cu")
		(net "FM_SUSACK_N")
	)
	(segment
		(start 181.795928 -59.865006)
		(end 163.896802 -59.865006)
		(width 0.127)
		(layer "In6.Cu")
		(net "FM_SUSACK_N")
	)
	(segment
		(start 199.39 -81.162652)
		(end 198.684896 -80.457548)
		(width 0.127)
		(layer "In6.Cu")
		(net "FM_SUSACK_N")
	)
	(segment
		(start 206.890874 -81.162652)
		(end 199.39 -81.162652)
		(width 0.127)
		(layer "In6.Cu")
		(net "FM_SUSACK_N")
	)
	(segment
		(start 213.228682 -87.50046)
		(end 206.890874 -81.162652)
		(width 0.127)
		(layer "In6.Cu")
		(net "FM_SUSACK_N")
	)
	(segment
		(start 192.93205 -78.152498)
		(end 191.165734 -78.152498)
		(width 0.127)
		(layer "In6.Cu")
		(net "FM_SUSACK_N")
	)
	(segment
		(start 289.422078 -59.1947)
		(end 283.829252 -64.787526)
		(width 0.127)
		(layer "In6.Cu")
		(net "FM_SUSACK_N")
	)
	(segment
		(start 244.396514 -82.324702)
		(end 239.220756 -87.50046)
		(width 0.127)
		(layer "In6.Cu")
		(net "FM_SUSACK_N")
	)
	(segment
		(start 191.165734 -78.152498)
		(end 185.909966 -72.89673)
		(width 0.127)
		(layer "In6.Cu")
		(net "FM_SUSACK_N")
	)
	(segment
		(start 283.829252 -64.787526)
		(end 283.829252 -74.641202)
		(width 0.127)
		(layer "In6.Cu")
		(net "FM_SUSACK_N")
	)
	(segment
		(start 185.909966 -63.979044)
		(end 181.795928 -59.865006)
		(width 0.127)
		(layer "In6.Cu")
		(net "FM_SUSACK_N")
	)
	(segment
		(start 185.909966 -72.89673)
		(end 185.909966 -63.979044)
		(width 0.127)
		(layer "In6.Cu")
		(net "FM_SUSACK_N")
	)
	(segment
		(start 276.145752 -82.324702)
		(end 244.396514 -82.324702)
		(width 0.127)
		(layer "In6.Cu")
		(net "FM_SUSACK_N")
	)
	(segment
		(start 198.684896 -80.457548)
		(end 195.2371 -80.457548)
		(width 0.127)
		(layer "In6.Cu")
		(net "FM_SUSACK_N")
	)
	(segment
		(start 325.253858 -40.461946)
		(end 320.166492 -35.37458)
		(width 0.127)
		(layer "In13.Cu")
		(net "FM_SUSACK_N")
	)
	(segment
		(start 309.94604 -36.416996)
		(end 309.94604 -39.391336)
		(width 0.127)
		(layer "In13.Cu")
		(net "FM_SUSACK_N")
	)
	(segment
		(start 312.013854 -36.289996)
		(end 310.07304 -36.289996)
		(width 0.127)
		(layer "In13.Cu")
		(net "FM_SUSACK_N")
	)
	(segment
		(start 299.687234 -46.591728)
		(end 298.308014 -47.970948)
		(width 0.127)
		(layer "In13.Cu")
		(net "FM_SUSACK_N")
	)
	(segment
		(start 328.625708 -40.461946)
		(end 325.253858 -40.461946)
		(width 0.127)
		(layer "In13.Cu")
		(net "FM_SUSACK_N")
	)
	(segment
		(start 309.94604 -39.391336)
		(end 302.745648 -46.591728)
		(width 0.127)
		(layer "In13.Cu")
		(net "FM_SUSACK_N")
	)
	(segment
		(start 293.6367 -49.329848)
		(end 293.6367 -50.574702)
		(width 0.127)
		(layer "In13.Cu")
		(net "FM_SUSACK_N")
	)
	(segment
		(start 320.166492 -35.37458)
		(end 312.92927 -35.37458)
		(width 0.127)
		(layer "In13.Cu")
		(net "FM_SUSACK_N")
	)
	(segment
		(start 293.6367 -50.574702)
		(end 289.422078 -54.789324)
		(width 0.127)
		(layer "In13.Cu")
		(net "FM_SUSACK_N")
	)
	(segment
		(start 289.422078 -54.789324)
		(end 289.422078 -57.728358)
		(width 0.127)
		(layer "In13.Cu")
		(net "FM_SUSACK_N")
	)
	(segment
		(start 310.07304 -36.289996)
		(end 309.94604 -36.416996)
		(width 0.127)
		(layer "In13.Cu")
		(net "FM_SUSACK_N")
	)
	(segment
		(start 298.308014 -47.970948)
		(end 294.9956 -47.970948)
		(width 0.127)
		(layer "In13.Cu")
		(net "FM_SUSACK_N")
	)
	(segment
		(start 294.9956 -47.970948)
		(end 293.6367 -49.329848)
		(width 0.127)
		(layer "In13.Cu")
		(net "FM_SUSACK_N")
	)
	(segment
		(start 312.92927 -35.37458)
		(end 312.013854 -36.289996)
		(width 0.127)
		(layer "In13.Cu")
		(net "FM_SUSACK_N")
	)
	(segment
		(start 302.745648 -46.591728)
		(end 299.687234 -46.591728)
		(width 0.127)
		(layer "In13.Cu")
		(net "FM_SUSACK_N")
	)
	(segment
		(start 332.422246 -42.341546)
		(end 331.881988 -42.341546)
		(width 0.12954)
		(layer "F.Cu")
		(net "FM_SPI_3V3_1V8_VOLTAGE")
	)
	(via
		(at 330.837286 -34.23793)
		(size 0.6604)
		(drill 0.3302)
		(layers "F.Cu" "B.Cu")
		(net "FM_SPI_3V3_1V8_VOLTAGE")
	)
	(via
		(at 331.881988 -42.341546)
		(size 0.4572)
		(drill 0.2032)
		(layers "F.Cu" "B.Cu")
		(net "FM_SPI_3V3_1V8_VOLTAGE")
	)
	(segment
		(start 330.15428 -34.920936)
		(end 330.837286 -34.23793)
		(width 0.12954)
		(layer "B.Cu")
		(net "FM_SPI_3V3_1V8_VOLTAGE")
	)
	(segment
		(start 331.881988 -42.341546)
		(end 331.574648 -41.617138)
		(width 0.0889)
		(layer "B.Cu")
		(net "FM_SPI_3V3_1V8_VOLTAGE")
	)
	(segment
		(start 330.743814 -41.119298)
		(end 330.728574 -41.092882)
		(width 0.0889)
		(layer "B.Cu")
		(net "FM_SPI_3V3_1V8_VOLTAGE")
	)
	(segment
		(start 331.13472 -33.100518)
		(end 330.17206 -33.100518)
		(width 0.12954)
		(layer "B.Cu")
		(net "FM_SPI_3V3_1V8_VOLTAGE")
	)
	(segment
		(start 330.728828 -40.763952)
		(end 330.728828 -40.763444)
		(width 0.0889)
		(layer "B.Cu")
		(net "FM_SPI_3V3_1V8_VOLTAGE")
	)
	(segment
		(start 331.574648 -41.617138)
		(end 331.558138 -41.588944)
		(width 0.0889)
		(layer "B.Cu")
		(net "FM_SPI_3V3_1V8_VOLTAGE")
	)
	(segment
		(start 330.782422 -39.722806)
		(end 330.782422 -39.351458)
		(width 0.0889)
		(layer "B.Cu")
		(net "FM_SPI_3V3_1V8_VOLTAGE")
	)
	(segment
		(start 330.782422 -38.699694)
		(end 330.858622 -38.623494)
		(width 0.12954)
		(layer "B.Cu")
		(net "FM_SPI_3V3_1V8_VOLTAGE")
	)
	(segment
		(start 330.858622 -38.623494)
		(end 330.858622 -37.04209)
		(width 0.12954)
		(layer "B.Cu")
		(net "FM_SPI_3V3_1V8_VOLTAGE")
	)
	(segment
		(start 330.837286 -34.23793)
		(end 330.837286 -33.422336)
		(width 0.12954)
		(layer "B.Cu")
		(net "FM_SPI_3V3_1V8_VOLTAGE")
	)
	(segment
		(start 330.858622 -37.04209)
		(end 330.15428 -36.337748)
		(width 0.12954)
		(layer "B.Cu")
		(net "FM_SPI_3V3_1V8_VOLTAGE")
	)
	(segment
		(start 330.782422 -39.351458)
		(end 330.782422 -38.699694)
		(width 0.12954)
		(layer "B.Cu")
		(net "FM_SPI_3V3_1V8_VOLTAGE")
	)
	(segment
		(start 331.069188 -41.306496)
		(end 331.067918 -41.306496)
		(width 0.0889)
		(layer "B.Cu")
		(net "FM_SPI_3V3_1V8_VOLTAGE")
	)
	(segment
		(start 331.146912 -33.11271)
		(end 331.13472 -33.100518)
		(width 0.12954)
		(layer "B.Cu")
		(net "FM_SPI_3V3_1V8_VOLTAGE")
	)
	(segment
		(start 330.765658 -39.74338)
		(end 330.782422 -39.722806)
		(width 0.0889)
		(layer "B.Cu")
		(net "FM_SPI_3V3_1V8_VOLTAGE")
	)
	(segment
		(start 330.837286 -33.422336)
		(end 331.146912 -33.11271)
		(width 0.12954)
		(layer "B.Cu")
		(net "FM_SPI_3V3_1V8_VOLTAGE")
	)
	(segment
		(start 330.15428 -36.337748)
		(end 330.15428 -34.920936)
		(width 0.12954)
		(layer "B.Cu")
		(net "FM_SPI_3V3_1V8_VOLTAGE")
	)
	(arc
		(start 331.067918 -41.306496)
		(mid 330.88078 -41.256332)
		(end 330.743814 -41.119298)
		(width 0.0889)
		(layer "B.Cu")
		(net "FM_SPI_3V3_1V8_VOLTAGE")
	)
	(arc
		(start 331.558138 -41.588944)
		(mid 331.351528 -41.382165)
		(end 331.069188 -41.306496)
		(width 0.0889)
		(layer "B.Cu")
		(net "FM_SPI_3V3_1V8_VOLTAGE")
	)
	(arc
		(start 330.728828 -40.763444)
		(mid 330.804672 -40.480742)
		(end 330.728828 -40.19804)
		(width 0.0889)
		(layer "B.Cu")
		(net "FM_SPI_3V3_1V8_VOLTAGE")
	)
	(arc
		(start 330.728828 -40.19804)
		(mid 330.676361 -39.964971)
		(end 330.765658 -39.74338)
		(width 0.0889)
		(layer "B.Cu")
		(net "FM_SPI_3V3_1V8_VOLTAGE")
	)
	(arc
		(start 330.728574 -41.092882)
		(mid 330.684552 -40.92837)
		(end 330.728828 -40.763952)
		(width 0.0889)
		(layer "B.Cu")
		(net "FM_SPI_3V3_1V8_VOLTAGE")
	)
	(segment
		(start 186.955684 -116.175536)
		(end 187.355734 -116.575586)
		(width 0.12954)
		(layer "F.Cu")
		(net "FM_SPD_REMOTE_EN_R")
	)
	(via
		(at 289.179 -148.935948)
		(size 0.508)
		(drill 0.254)
		(layers "F.Cu" "B.Cu")
		(net "FM_SPD_REMOTE_EN_R")
	)
	(via
		(at 187.355734 -116.575586)
		(size 0.4572)
		(drill 0.254)
		(layers "F.Cu" "B.Cu")
		(net "FM_SPD_REMOTE_EN_R")
	)
	(via
		(at 269.77848 -121.275348)
		(size 0.508)
		(drill 0.254)
		(layers "F.Cu" "B.Cu")
		(net "FM_SPD_REMOTE_EN_R")
	)
	(segment
		(start 289.179 -148.935948)
		(end 289.83559 -149.592538)
		(width 0.12954)
		(layer "B.Cu")
		(net "FM_SPD_REMOTE_EN_R")
	)
	(segment
		(start 289.83559 -149.592538)
		(end 290.948618 -149.592538)
		(width 0.12954)
		(layer "B.Cu")
		(net "FM_SPD_REMOTE_EN_R")
	)
	(segment
		(start 289.179 -148.935948)
		(end 285.623 -145.379948)
		(width 0.127)
		(layer "In2.Cu")
		(net "FM_SPD_REMOTE_EN_R")
	)
	(segment
		(start 279.038304 -145.379948)
		(end 269.65148 -135.993124)
		(width 0.127)
		(layer "In2.Cu")
		(net "FM_SPD_REMOTE_EN_R")
	)
	(segment
		(start 285.623 -145.379948)
		(end 279.038304 -145.379948)
		(width 0.127)
		(layer "In2.Cu")
		(net "FM_SPD_REMOTE_EN_R")
	)
	(segment
		(start 269.65148 -135.993124)
		(end 269.65148 -121.402348)
		(width 0.127)
		(layer "In2.Cu")
		(net "FM_SPD_REMOTE_EN_R")
	)
	(segment
		(start 269.65148 -121.402348)
		(end 269.77848 -121.275348)
		(width 0.127)
		(layer "In2.Cu")
		(net "FM_SPD_REMOTE_EN_R")
	)
	(segment
		(start 248.356882 -121.592848)
		(end 246.517922 -119.753888)
		(width 0.127)
		(layer "In15.Cu")
		(net "FM_SPD_REMOTE_EN_R")
	)
	(segment
		(start 187.659518 -116.575586)
		(end 187.355734 -116.575586)
		(width 0.127)
		(layer "In15.Cu")
		(net "FM_SPD_REMOTE_EN_R")
	)
	(segment
		(start 233.509058 -118.793768)
		(end 232.406698 -117.691408)
		(width 0.127)
		(layer "In15.Cu")
		(net "FM_SPD_REMOTE_EN_R")
	)
	(segment
		(start 236.833918 -118.793768)
		(end 233.509058 -118.793768)
		(width 0.127)
		(layer "In15.Cu")
		(net "FM_SPD_REMOTE_EN_R")
	)
	(segment
		(start 207.857852 -122.113548)
		(end 196.09308 -122.113548)
		(width 0.127)
		(layer "In15.Cu")
		(net "FM_SPD_REMOTE_EN_R")
	)
	(segment
		(start 214.959946 -122.0216)
		(end 212.008466 -122.0216)
		(width 0.127)
		(layer "In15.Cu")
		(net "FM_SPD_REMOTE_EN_R")
	)
	(segment
		(start 208.661 -121.3104)
		(end 207.857852 -122.113548)
		(width 0.127)
		(layer "In15.Cu")
		(net "FM_SPD_REMOTE_EN_R")
	)
	(segment
		(start 246.517922 -119.753888)
		(end 237.794038 -119.753888)
		(width 0.127)
		(layer "In15.Cu")
		(net "FM_SPD_REMOTE_EN_R")
	)
	(segment
		(start 219.290138 -117.691408)
		(end 214.959946 -122.0216)
		(width 0.127)
		(layer "In15.Cu")
		(net "FM_SPD_REMOTE_EN_R")
	)
	(segment
		(start 212.008466 -122.0216)
		(end 211.297266 -121.3104)
		(width 0.127)
		(layer "In15.Cu")
		(net "FM_SPD_REMOTE_EN_R")
	)
	(segment
		(start 211.297266 -121.3104)
		(end 208.661 -121.3104)
		(width 0.127)
		(layer "In15.Cu")
		(net "FM_SPD_REMOTE_EN_R")
	)
	(segment
		(start 195.28028 -121.300748)
		(end 193.751962 -121.300748)
		(width 0.127)
		(layer "In15.Cu")
		(net "FM_SPD_REMOTE_EN_R")
	)
	(segment
		(start 188.77915 -116.886228)
		(end 187.97016 -116.886228)
		(width 0.127)
		(layer "In15.Cu")
		(net "FM_SPD_REMOTE_EN_R")
	)
	(segment
		(start 269.77848 -121.275348)
		(end 269.46098 -121.592848)
		(width 0.127)
		(layer "In15.Cu")
		(net "FM_SPD_REMOTE_EN_R")
	)
	(segment
		(start 232.406698 -117.691408)
		(end 219.290138 -117.691408)
		(width 0.127)
		(layer "In15.Cu")
		(net "FM_SPD_REMOTE_EN_R")
	)
	(segment
		(start 187.97016 -116.886228)
		(end 187.659518 -116.575586)
		(width 0.127)
		(layer "In15.Cu")
		(net "FM_SPD_REMOTE_EN_R")
	)
	(segment
		(start 196.09308 -122.113548)
		(end 195.28028 -121.300748)
		(width 0.127)
		(layer "In15.Cu")
		(net "FM_SPD_REMOTE_EN_R")
	)
	(segment
		(start 237.794038 -119.753888)
		(end 236.833918 -118.793768)
		(width 0.127)
		(layer "In15.Cu")
		(net "FM_SPD_REMOTE_EN_R")
	)
	(segment
		(start 192.669414 -120.2182)
		(end 192.111122 -120.2182)
		(width 0.127)
		(layer "In15.Cu")
		(net "FM_SPD_REMOTE_EN_R")
	)
	(segment
		(start 193.751962 -121.300748)
		(end 192.669414 -120.2182)
		(width 0.127)
		(layer "In15.Cu")
		(net "FM_SPD_REMOTE_EN_R")
	)
	(segment
		(start 192.111122 -120.2182)
		(end 188.77915 -116.886228)
		(width 0.127)
		(layer "In15.Cu")
		(net "FM_SPD_REMOTE_EN_R")
	)
	(segment
		(start 269.46098 -121.592848)
		(end 248.356882 -121.592848)
		(width 0.127)
		(layer "In15.Cu")
		(net "FM_SPD_REMOTE_EN_R")
	)
	(segment
		(start 75.692 -149.32406)
		(end 76.268072 -149.900132)
		(width 0.12954)
		(layer "F.Cu")
		(net "FM_SPD_REMOTE_EN")
	)
	(segment
		(start 76.268072 -149.900132)
		(end 76.999338 -149.900132)
		(width 0.12954)
		(layer "F.Cu")
		(net "FM_SPD_REMOTE_EN")
	)
	(via
		(at 294.12692 -149.578568)
		(size 0.6604)
		(drill 0.3302)
		(layers "F.Cu" "B.Cu")
		(net "FM_SPD_REMOTE_EN")
	)
	(via
		(at 75.692 -149.32406)
		(size 0.508)
		(drill 0.254)
		(layers "F.Cu" "B.Cu")
		(net "FM_SPD_REMOTE_EN")
	)
	(via
		(at 290.313618 -150.392638)
		(size 0.508)
		(drill 0.254)
		(layers "F.Cu" "B.Cu")
		(net "FM_SPD_REMOTE_EN")
	)
	(segment
		(start 290.313618 -150.392638)
		(end 290.948618 -150.392638)
		(width 0.12954)
		(layer "B.Cu")
		(net "FM_SPD_REMOTE_EN")
	)
	(segment
		(start 292.980618 -150.392638)
		(end 293.31285 -150.392638)
		(width 0.12954)
		(layer "B.Cu")
		(net "FM_SPD_REMOTE_EN")
	)
	(segment
		(start 295.799002 -149.741128)
		(end 295.873932 -149.816058)
		(width 0.12954)
		(layer "B.Cu")
		(net "FM_SPD_REMOTE_EN")
	)
	(segment
		(start 294.12692 -149.578568)
		(end 294.28948 -149.741128)
		(width 0.12954)
		(layer "B.Cu")
		(net "FM_SPD_REMOTE_EN")
	)
	(segment
		(start 294.28948 -149.741128)
		(end 295.799002 -149.741128)
		(width 0.12954)
		(layer "B.Cu")
		(net "FM_SPD_REMOTE_EN")
	)
	(segment
		(start 293.31285 -150.392638)
		(end 294.12692 -149.578568)
		(width 0.12954)
		(layer "B.Cu")
		(net "FM_SPD_REMOTE_EN")
	)
	(segment
		(start 291.964618 -150.392638)
		(end 292.980618 -150.392638)
		(width 0.12954)
		(layer "B.Cu")
		(net "FM_SPD_REMOTE_EN")
	)
	(segment
		(start 290.948618 -150.392638)
		(end 291.964618 -150.392638)
		(width 0.12954)
		(layer "B.Cu")
		(net "FM_SPD_REMOTE_EN")
	)
	(segment
		(start 80.61706 -141.211808)
		(end 84.46516 -145.059908)
		(width 0.127)
		(layer "In13.Cu")
		(net "FM_SPD_REMOTE_EN")
	)
	(segment
		(start 118.5799 -154.437588)
		(end 134.98576 -170.843448)
		(width 0.127)
		(layer "In13.Cu")
		(net "FM_SPD_REMOTE_EN")
	)
	(segment
		(start 267.85316 -158.415228)
		(end 268.8463 -159.408368)
		(width 0.127)
		(layer "In13.Cu")
		(net "FM_SPD_REMOTE_EN")
	)
	(segment
		(start 78.89494 -141.211808)
		(end 80.61706 -141.211808)
		(width 0.127)
		(layer "In13.Cu")
		(net "FM_SPD_REMOTE_EN")
	)
	(segment
		(start 284.564074 -155.869894)
		(end 284.564074 -151.443182)
		(width 0.127)
		(layer "In13.Cu")
		(net "FM_SPD_REMOTE_EN")
	)
	(segment
		(start 84.46516 -145.059908)
		(end 84.46516 -150.269448)
		(width 0.127)
		(layer "In13.Cu")
		(net "FM_SPD_REMOTE_EN")
	)
	(segment
		(start 176.20488 -170.843448)
		(end 177.72634 -169.321988)
		(width 0.127)
		(layer "In13.Cu")
		(net "FM_SPD_REMOTE_EN")
	)
	(segment
		(start 134.98576 -170.843448)
		(end 176.20488 -170.843448)
		(width 0.127)
		(layer "In13.Cu")
		(net "FM_SPD_REMOTE_EN")
	)
	(segment
		(start 268.8463 -159.408368)
		(end 281.0256 -159.408368)
		(width 0.127)
		(layer "In13.Cu")
		(net "FM_SPD_REMOTE_EN")
	)
	(segment
		(start 88.6333 -154.437588)
		(end 118.5799 -154.437588)
		(width 0.127)
		(layer "In13.Cu")
		(net "FM_SPD_REMOTE_EN")
	)
	(segment
		(start 177.72634 -169.321988)
		(end 187.57392 -169.321988)
		(width 0.127)
		(layer "In13.Cu")
		(net "FM_SPD_REMOTE_EN")
	)
	(segment
		(start 75.692 -144.414748)
		(end 78.89494 -141.211808)
		(width 0.127)
		(layer "In13.Cu")
		(net "FM_SPD_REMOTE_EN")
	)
	(segment
		(start 217.6145 -158.415228)
		(end 267.85316 -158.415228)
		(width 0.127)
		(layer "In13.Cu")
		(net "FM_SPD_REMOTE_EN")
	)
	(segment
		(start 187.57392 -169.321988)
		(end 190.57874 -166.317168)
		(width 0.127)
		(layer "In13.Cu")
		(net "FM_SPD_REMOTE_EN")
	)
	(segment
		(start 209.71256 -166.317168)
		(end 217.6145 -158.415228)
		(width 0.127)
		(layer "In13.Cu")
		(net "FM_SPD_REMOTE_EN")
	)
	(segment
		(start 190.57874 -166.317168)
		(end 209.71256 -166.317168)
		(width 0.127)
		(layer "In13.Cu")
		(net "FM_SPD_REMOTE_EN")
	)
	(segment
		(start 281.0256 -159.408368)
		(end 284.564074 -155.869894)
		(width 0.127)
		(layer "In13.Cu")
		(net "FM_SPD_REMOTE_EN")
	)
	(segment
		(start 284.564074 -151.443182)
		(end 285.614618 -150.392638)
		(width 0.127)
		(layer "In13.Cu")
		(net "FM_SPD_REMOTE_EN")
	)
	(segment
		(start 84.46516 -150.269448)
		(end 88.6333 -154.437588)
		(width 0.127)
		(layer "In13.Cu")
		(net "FM_SPD_REMOTE_EN")
	)
	(segment
		(start 285.614618 -150.392638)
		(end 290.313618 -150.392638)
		(width 0.127)
		(layer "In13.Cu")
		(net "FM_SPD_REMOTE_EN")
	)
	(segment
		(start 75.692 -149.32406)
		(end 75.692 -144.414748)
		(width 0.127)
		(layer "In13.Cu")
		(net "FM_SPD_REMOTE_EN")
	)
	(via
		(at 89.9414 -183.068722)
		(size 0.762)
		(drill 0.254)
		(layers "F.Cu" "B.Cu")
		(net "FM_SMB_PEHPCPU1_PCIE_ALERT_R_N")
	)
	(segment
		(start 89.393522 -183.6166)
		(end 89.394284 -183.615838)
		(width 0.12954)
		(layer "B.Cu")
		(net "FM_SMB_PEHPCPU1_PCIE_ALERT_R_N")
	)
	(segment
		(start 88.401398 -183.6166)
		(end 89.393522 -183.6166)
		(width 0.12954)
		(layer "B.Cu")
		(net "FM_SMB_PEHPCPU1_PCIE_ALERT_R_N")
	)
	(segment
		(start 89.343484 -182.674514)
		(end 88.401398 -183.6166)
		(width 0.12954)
		(layer "B.Cu")
		(net "FM_SMB_PEHPCPU1_PCIE_ALERT_R_N")
	)
	(segment
		(start 89.9414 -183.068722)
		(end 89.394284 -183.615838)
		(width 0.12954)
		(layer "B.Cu")
		(net "FM_SMB_PEHPCPU1_PCIE_ALERT_R_N")
	)
	(segment
		(start 89.343484 -182.400448)
		(end 89.343484 -182.674514)
		(width 0.12954)
		(layer "B.Cu")
		(net "FM_SMB_PEHPCPU1_PCIE_ALERT_R_N")
	)
	(segment
		(start 89.883996 -184.013348)
		(end 89.631266 -184.266078)
		(width 0.12954)
		(layer "F.Cu")
		(net "FM_SMB_PEHPCPU1_PCIE_ALERT_N")
	)
	(segment
		(start 134.939532 -128.18491)
		(end 133.81101 -127.056388)
		(width 0.12954)
		(layer "F.Cu")
		(net "FM_SMB_PEHPCPU1_PCIE_ALERT_N")
	)
	(segment
		(start 110.39348 -136.083548)
		(end 109.42828 -136.083548)
		(width 0.12954)
		(layer "F.Cu")
		(net "FM_SMB_PEHPCPU1_PCIE_ALERT_N")
	)
	(segment
		(start 109.42828 -136.083548)
		(end 107.95508 -137.556748)
		(width 0.12954)
		(layer "F.Cu")
		(net "FM_SMB_PEHPCPU1_PCIE_ALERT_N")
	)
	(segment
		(start 107.95508 -168.493948)
		(end 92.43568 -184.013348)
		(width 0.12954)
		(layer "F.Cu")
		(net "FM_SMB_PEHPCPU1_PCIE_ALERT_N")
	)
	(segment
		(start 89.631266 -184.266078)
		(end 89.631266 -185.078878)
		(width 0.12954)
		(layer "F.Cu")
		(net "FM_SMB_PEHPCPU1_PCIE_ALERT_N")
	)
	(segment
		(start 134.939532 -128.390142)
		(end 134.939532 -128.18491)
		(width 0.12954)
		(layer "F.Cu")
		(net "FM_SMB_PEHPCPU1_PCIE_ALERT_N")
	)
	(segment
		(start 107.95508 -137.556748)
		(end 107.95508 -168.493948)
		(width 0.12954)
		(layer "F.Cu")
		(net "FM_SMB_PEHPCPU1_PCIE_ALERT_N")
	)
	(segment
		(start 92.43568 -184.013348)
		(end 89.883996 -184.013348)
		(width 0.12954)
		(layer "F.Cu")
		(net "FM_SMB_PEHPCPU1_PCIE_ALERT_N")
	)
	(via
		(at 304.402744 -395.272768)
		(size 0.762)
		(drill 0.254)
		(layers "F.Cu" "B.Cu")
		(net "FM_SMB_PEHPCPU1_PCIE_ALERT_N")
	)
	(via
		(at 134.939532 -128.390142)
		(size 0.508)
		(drill 0.254)
		(layers "F.Cu" "B.Cu")
		(net "FM_SMB_PEHPCPU1_PCIE_ALERT_N")
	)
	(via
		(at 89.631266 -185.078878)
		(size 0.508)
		(drill 0.254)
		(layers "F.Cu" "B.Cu")
		(net "FM_SMB_PEHPCPU1_PCIE_ALERT_N")
	)
	(via
		(at 235.57738 -207.038448)
		(size 0.508)
		(drill 0.254)
		(layers "F.Cu" "B.Cu")
		(net "FM_SMB_PEHPCPU1_PCIE_ALERT_N")
	)
	(via
		(at 222.03537 -192.276222)
		(size 0.508)
		(drill 0.254)
		(layers "F.Cu" "B.Cu")
		(net "FM_SMB_PEHPCPU1_PCIE_ALERT_N")
	)
	(via
		(at 110.39348 -136.083548)
		(size 0.508)
		(drill 0.254)
		(layers "F.Cu" "B.Cu")
		(net "FM_SMB_PEHPCPU1_PCIE_ALERT_N")
	)
	(via
		(at 196.693536 -188.998352)
		(size 0.508)
		(drill 0.254)
		(layers "F.Cu" "B.Cu")
		(net "FM_SMB_PEHPCPU1_PCIE_ALERT_N")
	)
	(segment
		(start 235.57738 -207.038448)
		(end 234.863132 -206.3242)
		(width 0.12954)
		(layer "B.Cu")
		(net "FM_SMB_PEHPCPU1_PCIE_ALERT_N")
	)
	(segment
		(start 134.939532 -134.422896)
		(end 133.27888 -136.083548)
		(width 0.12954)
		(layer "B.Cu")
		(net "FM_SMB_PEHPCPU1_PCIE_ALERT_N")
	)
	(segment
		(start 234.863132 -206.3242)
		(end 234.863132 -203.581)
		(width 0.12954)
		(layer "B.Cu")
		(net "FM_SMB_PEHPCPU1_PCIE_ALERT_N")
	)
	(segment
		(start 89.631266 -184.65292)
		(end 89.394284 -184.415938)
		(width 0.12954)
		(layer "B.Cu")
		(net "FM_SMB_PEHPCPU1_PCIE_ALERT_N")
	)
	(segment
		(start 89.631266 -185.078878)
		(end 89.631266 -184.65292)
		(width 0.12954)
		(layer "B.Cu")
		(net "FM_SMB_PEHPCPU1_PCIE_ALERT_N")
	)
	(segment
		(start 223.558354 -192.276222)
		(end 222.03537 -192.276222)
		(width 0.12954)
		(layer "B.Cu")
		(net "FM_SMB_PEHPCPU1_PCIE_ALERT_N")
	)
	(segment
		(start 133.27888 -136.083548)
		(end 110.39348 -136.083548)
		(width 0.12954)
		(layer "B.Cu")
		(net "FM_SMB_PEHPCPU1_PCIE_ALERT_N")
	)
	(segment
		(start 134.939532 -128.390142)
		(end 134.939532 -134.422896)
		(width 0.12954)
		(layer "B.Cu")
		(net "FM_SMB_PEHPCPU1_PCIE_ALERT_N")
	)
	(segment
		(start 234.863132 -203.581)
		(end 223.558354 -192.276222)
		(width 0.12954)
		(layer "B.Cu")
		(net "FM_SMB_PEHPCPU1_PCIE_ALERT_N")
	)
	(segment
		(start 283.68117 -388.22757)
		(end 283.68117 -389.4201)
		(width 0.127)
		(layer "In4.Cu")
		(net "FM_SMB_PEHPCPU1_PCIE_ALERT_N")
	)
	(segment
		(start 241.640614 -329.568556)
		(end 273.946874 -361.874816)
		(width 0.127)
		(layer "In4.Cu")
		(net "FM_SMB_PEHPCPU1_PCIE_ALERT_N")
	)
	(segment
		(start 300.045628 -395.351)
		(end 300.12386 -395.272768)
		(width 0.127)
		(layer "In4.Cu")
		(net "FM_SMB_PEHPCPU1_PCIE_ALERT_N")
	)
	(segment
		(start 273.946874 -361.874816)
		(end 273.946874 -377.451874)
		(width 0.127)
		(layer "In4.Cu")
		(net "FM_SMB_PEHPCPU1_PCIE_ALERT_N")
	)
	(segment
		(start 246.51208 -273.692874)
		(end 241.640614 -278.56434)
		(width 0.127)
		(layer "In4.Cu")
		(net "FM_SMB_PEHPCPU1_PCIE_ALERT_N")
	)
	(segment
		(start 246.51208 -217.973148)
		(end 246.51208 -273.692874)
		(width 0.127)
		(layer "In4.Cu")
		(net "FM_SMB_PEHPCPU1_PCIE_ALERT_N")
	)
	(segment
		(start 285.616142 -391.355072)
		(end 285.616142 -392.143742)
		(width 0.127)
		(layer "In4.Cu")
		(net "FM_SMB_PEHPCPU1_PCIE_ALERT_N")
	)
	(segment
		(start 300.12386 -395.272768)
		(end 304.402744 -395.272768)
		(width 0.127)
		(layer "In4.Cu")
		(net "FM_SMB_PEHPCPU1_PCIE_ALERT_N")
	)
	(segment
		(start 285.616142 -392.143742)
		(end 288.163 -394.6906)
		(width 0.127)
		(layer "In4.Cu")
		(net "FM_SMB_PEHPCPU1_PCIE_ALERT_N")
	)
	(segment
		(start 290.067746 -395.351)
		(end 300.045628 -395.351)
		(width 0.127)
		(layer "In4.Cu")
		(net "FM_SMB_PEHPCPU1_PCIE_ALERT_N")
	)
	(segment
		(start 279.7556 -383.2606)
		(end 280.568654 -383.2606)
		(width 0.127)
		(layer "In4.Cu")
		(net "FM_SMB_PEHPCPU1_PCIE_ALERT_N")
	)
	(segment
		(start 288.163 -394.6906)
		(end 289.407346 -394.6906)
		(width 0.127)
		(layer "In4.Cu")
		(net "FM_SMB_PEHPCPU1_PCIE_ALERT_N")
	)
	(segment
		(start 273.946874 -377.451874)
		(end 279.7556 -383.2606)
		(width 0.127)
		(layer "In4.Cu")
		(net "FM_SMB_PEHPCPU1_PCIE_ALERT_N")
	)
	(segment
		(start 289.407346 -394.6906)
		(end 290.067746 -395.351)
		(width 0.127)
		(layer "In4.Cu")
		(net "FM_SMB_PEHPCPU1_PCIE_ALERT_N")
	)
	(segment
		(start 235.57738 -207.038448)
		(end 246.51208 -217.973148)
		(width 0.127)
		(layer "In4.Cu")
		(net "FM_SMB_PEHPCPU1_PCIE_ALERT_N")
	)
	(segment
		(start 281.490928 -384.182874)
		(end 281.490928 -386.037328)
		(width 0.127)
		(layer "In4.Cu")
		(net "FM_SMB_PEHPCPU1_PCIE_ALERT_N")
	)
	(segment
		(start 281.490928 -386.037328)
		(end 283.68117 -388.22757)
		(width 0.127)
		(layer "In4.Cu")
		(net "FM_SMB_PEHPCPU1_PCIE_ALERT_N")
	)
	(segment
		(start 280.568654 -383.2606)
		(end 281.490928 -384.182874)
		(width 0.127)
		(layer "In4.Cu")
		(net "FM_SMB_PEHPCPU1_PCIE_ALERT_N")
	)
	(segment
		(start 283.68117 -389.4201)
		(end 285.616142 -391.355072)
		(width 0.127)
		(layer "In4.Cu")
		(net "FM_SMB_PEHPCPU1_PCIE_ALERT_N")
	)
	(segment
		(start 241.640614 -278.56434)
		(end 241.640614 -329.568556)
		(width 0.127)
		(layer "In4.Cu")
		(net "FM_SMB_PEHPCPU1_PCIE_ALERT_N")
	)
	(segment
		(start 427.00448 -399.100548)
		(end 425.04868 -397.144748)
		(width 0.127)
		(layer "In11.Cu")
		(net "FM_SMB_PEHPCPU1_PCIE_ALERT_N")
	)
	(segment
		(start 431.17008 -399.100548)
		(end 427.00448 -399.100548)
		(width 0.127)
		(layer "In11.Cu")
		(net "FM_SMB_PEHPCPU1_PCIE_ALERT_N")
	)
	(segment
		(start 437.64708 -405.577548)
		(end 431.17008 -399.100548)
		(width 0.127)
		(layer "In11.Cu")
		(net "FM_SMB_PEHPCPU1_PCIE_ALERT_N")
	)
	(segment
		(start 368.89182 -394.782548)
		(end 355.68128 -394.782548)
		(width 0.127)
		(layer "In11.Cu")
		(net "FM_SMB_PEHPCPU1_PCIE_ALERT_N")
	)
	(segment
		(start 371.296184 -394.129768)
		(end 369.5446 -394.129768)
		(width 0.127)
		(layer "In11.Cu")
		(net "FM_SMB_PEHPCPU1_PCIE_ALERT_N")
	)
	(segment
		(start 355.19106 -395.272768)
		(end 304.402744 -395.272768)
		(width 0.127)
		(layer "In11.Cu")
		(net "FM_SMB_PEHPCPU1_PCIE_ALERT_N")
	)
	(segment
		(start 222.03537 -192.276222)
		(end 217.059002 -187.299854)
		(width 0.127)
		(layer "In11.Cu")
		(net "FM_SMB_PEHPCPU1_PCIE_ALERT_N")
	)
	(segment
		(start 369.5446 -394.129768)
		(end 368.89182 -394.782548)
		(width 0.127)
		(layer "In11.Cu")
		(net "FM_SMB_PEHPCPU1_PCIE_ALERT_N")
	)
	(segment
		(start 437.64708 -409.387548)
		(end 437.64708 -405.577548)
		(width 0.127)
		(layer "In11.Cu")
		(net "FM_SMB_PEHPCPU1_PCIE_ALERT_N")
	)
	(segment
		(start 196.693536 -187.908438)
		(end 196.693536 -188.998352)
		(width 0.127)
		(layer "In11.Cu")
		(net "FM_SMB_PEHPCPU1_PCIE_ALERT_N")
	)
	(segment
		(start 217.059002 -187.299854)
		(end 197.30212 -187.299854)
		(width 0.127)
		(layer "In11.Cu")
		(net "FM_SMB_PEHPCPU1_PCIE_ALERT_N")
	)
	(segment
		(start 374.311164 -397.144748)
		(end 371.296184 -394.129768)
		(width 0.127)
		(layer "In11.Cu")
		(net "FM_SMB_PEHPCPU1_PCIE_ALERT_N")
	)
	(segment
		(start 425.04868 -397.144748)
		(end 374.311164 -397.144748)
		(width 0.127)
		(layer "In11.Cu")
		(net "FM_SMB_PEHPCPU1_PCIE_ALERT_N")
	)
	(segment
		(start 449.950078 -417.740084)
		(end 445.999616 -417.740084)
		(width 0.127)
		(layer "In11.Cu")
		(net "FM_SMB_PEHPCPU1_PCIE_ALERT_N")
	)
	(segment
		(start 445.999616 -417.740084)
		(end 437.64708 -409.387548)
		(width 0.127)
		(layer "In11.Cu")
		(net "FM_SMB_PEHPCPU1_PCIE_ALERT_N")
	)
	(segment
		(start 197.30212 -187.299854)
		(end 196.693536 -187.908438)
		(width 0.127)
		(layer "In11.Cu")
		(net "FM_SMB_PEHPCPU1_PCIE_ALERT_N")
	)
	(segment
		(start 355.68128 -394.782548)
		(end 355.19106 -395.272768)
		(width 0.127)
		(layer "In11.Cu")
		(net "FM_SMB_PEHPCPU1_PCIE_ALERT_N")
	)
	(segment
		(start 193.497708 -191.455548)
		(end 167.093646 -191.455548)
		(width 0.127)
		(layer "In13.Cu")
		(net "FM_SMB_PEHPCPU1_PCIE_ALERT_N")
	)
	(segment
		(start 95.86468 -187.772548)
		(end 91.87688 -183.784748)
		(width 0.127)
		(layer "In13.Cu")
		(net "FM_SMB_PEHPCPU1_PCIE_ALERT_N")
	)
	(segment
		(start 89.631266 -183.998362)
		(end 89.631266 -185.078878)
		(width 0.127)
		(layer "In13.Cu")
		(net "FM_SMB_PEHPCPU1_PCIE_ALERT_N")
	)
	(segment
		(start 167.093646 -191.455548)
		(end 161.988246 -186.350148)
		(width 0.127)
		(layer "In13.Cu")
		(net "FM_SMB_PEHPCPU1_PCIE_ALERT_N")
	)
	(segment
		(start 89.84488 -183.784748)
		(end 89.631266 -183.998362)
		(width 0.127)
		(layer "In13.Cu")
		(net "FM_SMB_PEHPCPU1_PCIE_ALERT_N")
	)
	(segment
		(start 99.09048 -186.350148)
		(end 97.66808 -187.772548)
		(width 0.127)
		(layer "In13.Cu")
		(net "FM_SMB_PEHPCPU1_PCIE_ALERT_N")
	)
	(segment
		(start 196.693536 -188.998352)
		(end 195.954904 -188.998352)
		(width 0.127)
		(layer "In13.Cu")
		(net "FM_SMB_PEHPCPU1_PCIE_ALERT_N")
	)
	(segment
		(start 195.954904 -188.998352)
		(end 193.497708 -191.455548)
		(width 0.127)
		(layer "In13.Cu")
		(net "FM_SMB_PEHPCPU1_PCIE_ALERT_N")
	)
	(segment
		(start 97.66808 -187.772548)
		(end 95.86468 -187.772548)
		(width 0.127)
		(layer "In13.Cu")
		(net "FM_SMB_PEHPCPU1_PCIE_ALERT_N")
	)
	(segment
		(start 161.988246 -186.350148)
		(end 99.09048 -186.350148)
		(width 0.127)
		(layer "In13.Cu")
		(net "FM_SMB_PEHPCPU1_PCIE_ALERT_N")
	)
	(segment
		(start 91.87688 -183.784748)
		(end 89.84488 -183.784748)
		(width 0.127)
		(layer "In13.Cu")
		(net "FM_SMB_PEHPCPU1_PCIE_ALERT_N")
	)
	(via
		(at 363.244638 -184.56529)
		(size 0.6604)
		(drill 0.3302)
		(layers "F.Cu" "B.Cu")
		(net "FM_SMB_PEHPCPU0_PCIE_ALERT_R_N")
	)
	(segment
		(start 363.136688 -183.373014)
		(end 363.136688 -182.33771)
		(width 0.12954)
		(layer "B.Cu")
		(net "FM_SMB_PEHPCPU0_PCIE_ALERT_R_N")
	)
	(segment
		(start 363.13745 -183.373776)
		(end 363.13745 -183.968136)
		(width 0.12954)
		(layer "B.Cu")
		(net "FM_SMB_PEHPCPU0_PCIE_ALERT_R_N")
	)
	(segment
		(start 363.244638 -184.56529)
		(end 364.854998 -184.56529)
		(width 0.12954)
		(layer "B.Cu")
		(net "FM_SMB_PEHPCPU0_PCIE_ALERT_R_N")
	)
	(segment
		(start 363.244638 -184.075324)
		(end 363.244638 -184.56529)
		(width 0.12954)
		(layer "B.Cu")
		(net "FM_SMB_PEHPCPU0_PCIE_ALERT_R_N")
	)
	(segment
		(start 363.13745 -183.373776)
		(end 363.136688 -183.373014)
		(width 0.12954)
		(layer "B.Cu")
		(net "FM_SMB_PEHPCPU0_PCIE_ALERT_R_N")
	)
	(segment
		(start 365.037624 -184.382664)
		(end 365.037624 -184.051448)
		(width 0.12954)
		(layer "B.Cu")
		(net "FM_SMB_PEHPCPU0_PCIE_ALERT_R_N")
	)
	(segment
		(start 364.854998 -184.56529)
		(end 365.037624 -184.382664)
		(width 0.12954)
		(layer "B.Cu")
		(net "FM_SMB_PEHPCPU0_PCIE_ALERT_R_N")
	)
	(segment
		(start 363.13745 -183.968136)
		(end 363.244638 -184.075324)
		(width 0.12954)
		(layer "B.Cu")
		(net "FM_SMB_PEHPCPU0_PCIE_ALERT_R_N")
	)
	(segment
		(start 414.96742 -141.140688)
		(end 392.24204 -141.140688)
		(width 0.12954)
		(layer "F.Cu")
		(net "FM_SMB_PEHPCPU0_PCIE_ALERT_N")
	)
	(segment
		(start 374.872758 -161.51225)
		(end 350.587818 -161.51225)
		(width 0.12954)
		(layer "F.Cu")
		(net "FM_SMB_PEHPCPU0_PCIE_ALERT_N")
	)
	(segment
		(start 378.49048 -154.892248)
		(end 378.49048 -157.894528)
		(width 0.12954)
		(layer "F.Cu")
		(net "FM_SMB_PEHPCPU0_PCIE_ALERT_N")
	)
	(segment
		(start 449.573904 -119.454422)
		(end 446.8622 -122.166126)
		(width 0.12954)
		(layer "F.Cu")
		(net "FM_SMB_PEHPCPU0_PCIE_ALERT_N")
	)
	(segment
		(start 444.53175 -145.449798)
		(end 419.27653 -145.449798)
		(width 0.12954)
		(layer "F.Cu")
		(net "FM_SMB_PEHPCPU0_PCIE_ALERT_N")
	)
	(segment
		(start 350.587818 -161.51225)
		(end 345.286838 -166.81323)
		(width 0.12954)
		(layer "F.Cu")
		(net "FM_SMB_PEHPCPU0_PCIE_ALERT_N")
	)
	(segment
		(start 345.286838 -171.12869)
		(end 344.435938 -171.97959)
		(width 0.12954)
		(layer "F.Cu")
		(net "FM_SMB_PEHPCPU0_PCIE_ALERT_N")
	)
	(segment
		(start 446.8622 -143.119348)
		(end 444.53175 -145.449798)
		(width 0.12954)
		(layer "F.Cu")
		(net "FM_SMB_PEHPCPU0_PCIE_ALERT_N")
	)
	(segment
		(start 419.27653 -145.449798)
		(end 414.96742 -141.140688)
		(width 0.12954)
		(layer "F.Cu")
		(net "FM_SMB_PEHPCPU0_PCIE_ALERT_N")
	)
	(segment
		(start 392.24204 -141.140688)
		(end 378.49048 -154.892248)
		(width 0.12954)
		(layer "F.Cu")
		(net "FM_SMB_PEHPCPU0_PCIE_ALERT_N")
	)
	(segment
		(start 378.49048 -157.894528)
		(end 374.872758 -161.51225)
		(width 0.12954)
		(layer "F.Cu")
		(net "FM_SMB_PEHPCPU0_PCIE_ALERT_N")
	)
	(segment
		(start 446.8622 -122.166126)
		(end 446.8622 -143.119348)
		(width 0.12954)
		(layer "F.Cu")
		(net "FM_SMB_PEHPCPU0_PCIE_ALERT_N")
	)
	(segment
		(start 345.286838 -166.81323)
		(end 345.286838 -171.12869)
		(width 0.12954)
		(layer "F.Cu")
		(net "FM_SMB_PEHPCPU0_PCIE_ALERT_N")
	)
	(segment
		(start 344.435938 -171.97959)
		(end 344.435938 -172.72)
		(width 0.12954)
		(layer "F.Cu")
		(net "FM_SMB_PEHPCPU0_PCIE_ALERT_N")
	)
	(segment
		(start 449.573904 -119.429022)
		(end 449.573904 -119.454422)
		(width 0.12954)
		(layer "F.Cu")
		(net "FM_SMB_PEHPCPU0_PCIE_ALERT_N")
	)
	(via
		(at 236.619542 -207.291686)
		(size 0.508)
		(drill 0.254)
		(layers "F.Cu" "B.Cu")
		(net "FM_SMB_PEHPCPU0_PCIE_ALERT_N")
	)
	(via
		(at 344.435938 -172.72)
		(size 0.508)
		(drill 0.254)
		(layers "F.Cu" "B.Cu")
		(net "FM_SMB_PEHPCPU0_PCIE_ALERT_N")
	)
	(via
		(at 301.68088 -394.637768)
		(size 0.508)
		(drill 0.254)
		(layers "F.Cu" "B.Cu")
		(net "FM_SMB_PEHPCPU0_PCIE_ALERT_N")
	)
	(segment
		(start 347.610938 -180.67147)
		(end 352.848418 -180.67147)
		(width 0.12954)
		(layer "B.Cu")
		(net "FM_SMB_PEHPCPU0_PCIE_ALERT_N")
	)
	(segment
		(start 344.435938 -172.72)
		(end 344.435938 -177.49647)
		(width 0.12954)
		(layer "B.Cu")
		(net "FM_SMB_PEHPCPU0_PCIE_ALERT_N")
	)
	(segment
		(start 355.550724 -183.373776)
		(end 362.33735 -183.373776)
		(width 0.12954)
		(layer "B.Cu")
		(net "FM_SMB_PEHPCPU0_PCIE_ALERT_N")
	)
	(segment
		(start 352.848418 -180.67147)
		(end 355.550724 -183.373776)
		(width 0.12954)
		(layer "B.Cu")
		(net "FM_SMB_PEHPCPU0_PCIE_ALERT_N")
	)
	(segment
		(start 344.435938 -177.49647)
		(end 347.610938 -180.67147)
		(width 0.12954)
		(layer "B.Cu")
		(net "FM_SMB_PEHPCPU0_PCIE_ALERT_N")
	)
	(segment
		(start 284.11297 -389.24103)
		(end 284.11297 -385.99237)
		(width 0.127)
		(layer "In4.Cu")
		(net "FM_SMB_PEHPCPU0_PCIE_ALERT_N")
	)
	(segment
		(start 284.11297 -385.99237)
		(end 280.6954 -382.5748)
		(width 0.127)
		(layer "In4.Cu")
		(net "FM_SMB_PEHPCPU0_PCIE_ALERT_N")
	)
	(segment
		(start 279.908 -382.5748)
		(end 274.581874 -377.248674)
		(width 0.127)
		(layer "In4.Cu")
		(net "FM_SMB_PEHPCPU0_PCIE_ALERT_N")
	)
	(segment
		(start 290.673536 -393.04976)
		(end 287.9217 -393.04976)
		(width 0.127)
		(layer "In4.Cu")
		(net "FM_SMB_PEHPCPU0_PCIE_ALERT_N")
	)
	(segment
		(start 242.275614 -329.305412)
		(end 242.275614 -278.827484)
		(width 0.127)
		(layer "In4.Cu")
		(net "FM_SMB_PEHPCPU0_PCIE_ALERT_N")
	)
	(segment
		(start 287.9217 -393.04976)
		(end 284.11297 -389.24103)
		(width 0.127)
		(layer "In4.Cu")
		(net "FM_SMB_PEHPCPU0_PCIE_ALERT_N")
	)
	(segment
		(start 291.083746 -394.78458)
		(end 290.800536 -394.50137)
		(width 0.127)
		(layer "In4.Cu")
		(net "FM_SMB_PEHPCPU0_PCIE_ALERT_N")
	)
	(segment
		(start 280.6954 -382.5748)
		(end 279.908 -382.5748)
		(width 0.127)
		(layer "In4.Cu")
		(net "FM_SMB_PEHPCPU0_PCIE_ALERT_N")
	)
	(segment
		(start 301.68088 -394.637768)
		(end 301.534068 -394.78458)
		(width 0.127)
		(layer "In4.Cu")
		(net "FM_SMB_PEHPCPU0_PCIE_ALERT_N")
	)
	(segment
		(start 274.581874 -361.611672)
		(end 242.275614 -329.305412)
		(width 0.127)
		(layer "In4.Cu")
		(net "FM_SMB_PEHPCPU0_PCIE_ALERT_N")
	)
	(segment
		(start 301.534068 -394.78458)
		(end 291.083746 -394.78458)
		(width 0.127)
		(layer "In4.Cu")
		(net "FM_SMB_PEHPCPU0_PCIE_ALERT_N")
	)
	(segment
		(start 242.275614 -278.827484)
		(end 246.94388 -274.159218)
		(width 0.127)
		(layer "In4.Cu")
		(net "FM_SMB_PEHPCPU0_PCIE_ALERT_N")
	)
	(segment
		(start 290.800536 -394.50137)
		(end 290.800536 -393.17676)
		(width 0.127)
		(layer "In4.Cu")
		(net "FM_SMB_PEHPCPU0_PCIE_ALERT_N")
	)
	(segment
		(start 246.94388 -274.159218)
		(end 246.94388 -217.616024)
		(width 0.127)
		(layer "In4.Cu")
		(net "FM_SMB_PEHPCPU0_PCIE_ALERT_N")
	)
	(segment
		(start 274.581874 -377.248674)
		(end 274.581874 -361.611672)
		(width 0.127)
		(layer "In4.Cu")
		(net "FM_SMB_PEHPCPU0_PCIE_ALERT_N")
	)
	(segment
		(start 290.800536 -393.17676)
		(end 290.673536 -393.04976)
		(width 0.127)
		(layer "In4.Cu")
		(net "FM_SMB_PEHPCPU0_PCIE_ALERT_N")
	)
	(segment
		(start 246.94388 -217.616024)
		(end 236.619542 -207.291686)
		(width 0.127)
		(layer "In4.Cu")
		(net "FM_SMB_PEHPCPU0_PCIE_ALERT_N")
	)
	(segment
		(start 424.74388 -396.154148)
		(end 374.721628 -396.154148)
		(width 0.127)
		(layer "In11.Cu")
		(net "FM_SMB_PEHPCPU0_PCIE_ALERT_N")
	)
	(segment
		(start 355.211126 -394.637768)
		(end 301.68088 -394.637768)
		(width 0.127)
		(layer "In11.Cu")
		(net "FM_SMB_PEHPCPU0_PCIE_ALERT_N")
	)
	(segment
		(start 431.60188 -398.236948)
		(end 426.82668 -398.236948)
		(width 0.127)
		(layer "In11.Cu")
		(net "FM_SMB_PEHPCPU0_PCIE_ALERT_N")
	)
	(segment
		(start 446.025016 -412.660084)
		(end 431.60188 -398.236948)
		(width 0.127)
		(layer "In11.Cu")
		(net "FM_SMB_PEHPCPU0_PCIE_ALERT_N")
	)
	(segment
		(start 449.950078 -412.660084)
		(end 446.025016 -412.660084)
		(width 0.127)
		(layer "In11.Cu")
		(net "FM_SMB_PEHPCPU0_PCIE_ALERT_N")
	)
	(segment
		(start 426.82668 -398.236948)
		(end 424.74388 -396.154148)
		(width 0.127)
		(layer "In11.Cu")
		(net "FM_SMB_PEHPCPU0_PCIE_ALERT_N")
	)
	(segment
		(start 355.538786 -394.310108)
		(end 355.211126 -394.637768)
		(width 0.127)
		(layer "In11.Cu")
		(net "FM_SMB_PEHPCPU0_PCIE_ALERT_N")
	)
	(segment
		(start 372.219728 -393.652248)
		(end 369.31092 -393.652248)
		(width 0.127)
		(layer "In11.Cu")
		(net "FM_SMB_PEHPCPU0_PCIE_ALERT_N")
	)
	(segment
		(start 369.31092 -393.652248)
		(end 368.65306 -394.310108)
		(width 0.127)
		(layer "In11.Cu")
		(net "FM_SMB_PEHPCPU0_PCIE_ALERT_N")
	)
	(segment
		(start 374.721628 -396.154148)
		(end 372.219728 -393.652248)
		(width 0.127)
		(layer "In11.Cu")
		(net "FM_SMB_PEHPCPU0_PCIE_ALERT_N")
	)
	(segment
		(start 368.65306 -394.310108)
		(end 355.538786 -394.310108)
		(width 0.127)
		(layer "In11.Cu")
		(net "FM_SMB_PEHPCPU0_PCIE_ALERT_N")
	)
	(segment
		(start 298.615608 -191.182498)
		(end 254.89789 -191.182498)
		(width 0.127)
		(layer "In13.Cu")
		(net "FM_SMB_PEHPCPU0_PCIE_ALERT_N")
	)
	(segment
		(start 344.435938 -172.72)
		(end 344.435938 -185.81878)
		(width 0.127)
		(layer "In13.Cu")
		(net "FM_SMB_PEHPCPU0_PCIE_ALERT_N")
	)
	(segment
		(start 339.544406 -190.710312)
		(end 321.203828 -190.710312)
		(width 0.127)
		(layer "In13.Cu")
		(net "FM_SMB_PEHPCPU0_PCIE_ALERT_N")
	)
	(segment
		(start 301.375318 -193.942208)
		(end 298.615608 -191.182498)
		(width 0.127)
		(layer "In13.Cu")
		(net "FM_SMB_PEHPCPU0_PCIE_ALERT_N")
	)
	(segment
		(start 318.372236 -193.541904)
		(end 307.775356 -193.541904)
		(width 0.127)
		(layer "In13.Cu")
		(net "FM_SMB_PEHPCPU0_PCIE_ALERT_N")
	)
	(segment
		(start 254.89789 -191.182498)
		(end 238.788702 -207.291686)
		(width 0.127)
		(layer "In13.Cu")
		(net "FM_SMB_PEHPCPU0_PCIE_ALERT_N")
	)
	(segment
		(start 307.375052 -193.942208)
		(end 301.375318 -193.942208)
		(width 0.127)
		(layer "In13.Cu")
		(net "FM_SMB_PEHPCPU0_PCIE_ALERT_N")
	)
	(segment
		(start 321.203828 -190.710312)
		(end 318.372236 -193.541904)
		(width 0.127)
		(layer "In13.Cu")
		(net "FM_SMB_PEHPCPU0_PCIE_ALERT_N")
	)
	(segment
		(start 307.775356 -193.541904)
		(end 307.375052 -193.942208)
		(width 0.127)
		(layer "In13.Cu")
		(net "FM_SMB_PEHPCPU0_PCIE_ALERT_N")
	)
	(segment
		(start 238.788702 -207.291686)
		(end 236.619542 -207.291686)
		(width 0.127)
		(layer "In13.Cu")
		(net "FM_SMB_PEHPCPU0_PCIE_ALERT_N")
	)
	(segment
		(start 344.435938 -185.81878)
		(end 339.544406 -190.710312)
		(width 0.127)
		(layer "In13.Cu")
		(net "FM_SMB_PEHPCPU0_PCIE_ALERT_N")
	)
	(via
		(at 89.261188 -178.046888)
		(size 0.6604)
		(drill 0.3302)
		(layers "F.Cu" "B.Cu")
		(net "FM_SMB_CPU1_ALERT_R1")
	)
	(segment
		(start 89.343484 -180.500528)
		(end 89.343484 -179.397406)
		(width 0.12954)
		(layer "B.Cu")
		(net "FM_SMB_CPU1_ALERT_R1")
	)
	(segment
		(start 89.33053 -180.513482)
		(end 89.33053 -180.948838)
		(width 0.12954)
		(layer "B.Cu")
		(net "FM_SMB_CPU1_ALERT_R1")
	)
	(segment
		(start 89.234518 -181.04485)
		(end 88.800432 -181.04485)
		(width 0.12954)
		(layer "B.Cu")
		(net "FM_SMB_CPU1_ALERT_R1")
	)
	(segment
		(start 89.343484 -180.500528)
		(end 89.33053 -180.513482)
		(width 0.12954)
		(layer "B.Cu")
		(net "FM_SMB_CPU1_ALERT_R1")
	)
	(segment
		(start 89.261188 -179.31511)
		(end 89.261188 -178.046888)
		(width 0.12954)
		(layer "B.Cu")
		(net "FM_SMB_CPU1_ALERT_R1")
	)
	(segment
		(start 89.33053 -180.948838)
		(end 89.234518 -181.04485)
		(width 0.12954)
		(layer "B.Cu")
		(net "FM_SMB_CPU1_ALERT_R1")
	)
	(segment
		(start 88.693498 -180.937916)
		(end 88.693498 -180.500528)
		(width 0.12954)
		(layer "B.Cu")
		(net "FM_SMB_CPU1_ALERT_R1")
	)
	(segment
		(start 89.343484 -179.397406)
		(end 89.261188 -179.31511)
		(width 0.12954)
		(layer "B.Cu")
		(net "FM_SMB_CPU1_ALERT_R1")
	)
	(segment
		(start 88.800432 -181.04485)
		(end 88.693498 -180.937916)
		(width 0.12954)
		(layer "B.Cu")
		(net "FM_SMB_CPU1_ALERT_R1")
	)
	(via
		(at 363.851698 -180.97119)
		(size 0.6604)
		(drill 0.3302)
		(layers "F.Cu" "B.Cu")
		(net "FM_SMB_CPU0_ALERT_R1")
	)
	(segment
		(start 365.006128 -180.97119)
		(end 365.028988 -180.99405)
		(width 0.12954)
		(layer "B.Cu")
		(net "FM_SMB_CPU0_ALERT_R1")
	)
	(segment
		(start 365.037624 -182.151528)
		(end 365.028988 -182.142892)
		(width 0.12954)
		(layer "B.Cu")
		(net "FM_SMB_CPU0_ALERT_R1")
	)
	(segment
		(start 363.851698 -180.97119)
		(end 365.006128 -180.97119)
		(width 0.12954)
		(layer "B.Cu")
		(net "FM_SMB_CPU0_ALERT_R1")
	)
	(segment
		(start 364.387638 -182.151528)
		(end 365.037624 -182.151528)
		(width 0.12954)
		(layer "B.Cu")
		(net "FM_SMB_CPU0_ALERT_R1")
	)
	(segment
		(start 365.028988 -182.142892)
		(end 365.028988 -180.99405)
		(width 0.12954)
		(layer "B.Cu")
		(net "FM_SMB_CPU0_ALERT_R1")
	)
	(segment
		(start 454.698862 -118.541546)
		(end 451.72122 -118.541546)
		(width 0.12954)
		(layer "F.Cu")
		(net "FM_SMB_CPU0_ALERT")
	)
	(segment
		(start 454.798684 -118.641368)
		(end 454.698862 -118.541546)
		(width 0.12954)
		(layer "F.Cu")
		(net "FM_SMB_CPU0_ALERT")
	)
	(segment
		(start 451.26148 -118.541546)
		(end 450.374004 -119.429022)
		(width 0.12954)
		(layer "F.Cu")
		(net "FM_SMB_CPU0_ALERT")
	)
	(segment
		(start 451.72122 -118.541546)
		(end 451.26148 -118.541546)
		(width 0.12954)
		(layer "F.Cu")
		(net "FM_SMB_CPU0_ALERT")
	)
	(via
		(at 451.72122 -118.541546)
		(size 0.762)
		(drill 0.381)
		(layers "F.Cu" "B.Cu")
		(net "FM_SMB_CPU0_ALERT")
	)
	(segment
		(start 171.755562 -111.375444)
		(end 171.355512 -110.975394)
		(width 0.12954)
		(layer "F.Cu")
		(net "FM_SLP_SUS_RSM_RST_N")
	)
	(via
		(at 311.3278 -27.676348)
		(size 0.762)
		(drill 0.254)
		(layers "F.Cu" "B.Cu")
		(net "FM_SLP_SUS_RSM_RST_N")
	)
	(via
		(at 171.355512 -110.975394)
		(size 0.4572)
		(drill 0.254)
		(layers "F.Cu" "B.Cu")
		(net "FM_SLP_SUS_RSM_RST_N")
	)
	(segment
		(start 165.04793 -111.470948)
		(end 165.468554 -111.470948)
		(width 0.12954)
		(layer "B.Cu")
		(net "FM_SLP_SUS_RSM_RST_N")
	)
	(segment
		(start 313.867546 -30.522926)
		(end 313.365896 -29.311854)
		(width 0.12954)
		(layer "B.Cu")
		(net "FM_SLP_SUS_RSM_RST_N")
	)
	(segment
		(start 317.349632 -35.573716)
		(end 317.349632 -36.377372)
		(width 0.12954)
		(layer "B.Cu")
		(net "FM_SLP_SUS_RSM_RST_N")
	)
	(segment
		(start 317.112396 -33.767776)
		(end 313.867546 -30.522926)
		(width 0.12954)
		(layer "B.Cu")
		(net "FM_SLP_SUS_RSM_RST_N")
	)
	(segment
		(start 317.112396 -35.33648)
		(end 317.112396 -33.767776)
		(width 0.12954)
		(layer "B.Cu")
		(net "FM_SLP_SUS_RSM_RST_N")
	)
	(segment
		(start 318.261746 -37.289486)
		(end 318.874648 -37.289486)
		(width 0.12954)
		(layer "B.Cu")
		(net "FM_SLP_SUS_RSM_RST_N")
	)
	(segment
		(start 313.365896 -29.311854)
		(end 313.10453 -29.050488)
		(width 0.12954)
		(layer "B.Cu")
		(net "FM_SLP_SUS_RSM_RST_N")
	)
	(segment
		(start 165.491414 -111.448088)
		(end 170.657266 -111.448088)
		(width 0.12954)
		(layer "B.Cu")
		(net "FM_SLP_SUS_RSM_RST_N")
	)
	(segment
		(start 319.415414 -37.513514)
		(end 320.413888 -38.511988)
		(width 0.12954)
		(layer "B.Cu")
		(net "FM_SLP_SUS_RSM_RST_N")
	)
	(segment
		(start 165.468554 -111.470948)
		(end 165.491414 -111.448088)
		(width 0.12954)
		(layer "B.Cu")
		(net "FM_SLP_SUS_RSM_RST_N")
	)
	(segment
		(start 320.413888 -38.511988)
		(end 321.797426 -38.511988)
		(width 0.12954)
		(layer "B.Cu")
		(net "FM_SLP_SUS_RSM_RST_N")
	)
	(segment
		(start 171.12996 -110.975394)
		(end 171.355512 -110.975394)
		(width 0.12954)
		(layer "B.Cu")
		(net "FM_SLP_SUS_RSM_RST_N")
	)
	(segment
		(start 318.874648 -37.289486)
		(end 319.415414 -37.513514)
		(width 0.12954)
		(layer "B.Cu")
		(net "FM_SLP_SUS_RSM_RST_N")
	)
	(segment
		(start 317.349632 -35.573716)
		(end 317.112396 -35.33648)
		(width 0.12954)
		(layer "B.Cu")
		(net "FM_SLP_SUS_RSM_RST_N")
	)
	(segment
		(start 170.657266 -111.448088)
		(end 171.12996 -110.975394)
		(width 0.12954)
		(layer "B.Cu")
		(net "FM_SLP_SUS_RSM_RST_N")
	)
	(segment
		(start 311.3278 -28.665932)
		(end 311.3278 -27.676348)
		(width 0.12954)
		(layer "B.Cu")
		(net "FM_SLP_SUS_RSM_RST_N")
	)
	(segment
		(start 313.10453 -29.050488)
		(end 311.712356 -29.050488)
		(width 0.12954)
		(layer "B.Cu")
		(net "FM_SLP_SUS_RSM_RST_N")
	)
	(segment
		(start 317.349632 -36.377372)
		(end 318.261746 -37.289486)
		(width 0.12954)
		(layer "B.Cu")
		(net "FM_SLP_SUS_RSM_RST_N")
	)
	(segment
		(start 311.712356 -29.050488)
		(end 311.3278 -28.665932)
		(width 0.12954)
		(layer "B.Cu")
		(net "FM_SLP_SUS_RSM_RST_N")
	)
	(segment
		(start 239.045496 -89.100914)
		(end 244.59946 -83.54695)
		(width 0.127)
		(layer "In13.Cu")
		(net "FM_SLP_SUS_RSM_RST_N")
	)
	(segment
		(start 305.77282 -35.121088)
		(end 307.06822 -33.825688)
		(width 0.127)
		(layer "In13.Cu")
		(net "FM_SLP_SUS_RSM_RST_N")
	)
	(segment
		(start 307.06822 -28.943808)
		(end 308.33568 -27.676348)
		(width 0.127)
		(layer "In13.Cu")
		(net "FM_SLP_SUS_RSM_RST_N")
	)
	(segment
		(start 286.131 -74.927206)
		(end 286.131 -59.732926)
		(width 0.127)
		(layer "In13.Cu")
		(net "FM_SLP_SUS_RSM_RST_N")
	)
	(segment
		(start 302.26762 -45.590968)
		(end 305.77282 -42.085768)
		(width 0.127)
		(layer "In13.Cu")
		(net "FM_SLP_SUS_RSM_RST_N")
	)
	(segment
		(start 171.46778 -100.841048)
		(end 171.46778 -98.44913)
		(width 0.127)
		(layer "In13.Cu")
		(net "FM_SLP_SUS_RSM_RST_N")
	)
	(segment
		(start 218.578938 -85.672168)
		(end 222.007684 -89.100914)
		(width 0.127)
		(layer "In13.Cu")
		(net "FM_SLP_SUS_RSM_RST_N")
	)
	(segment
		(start 172.93209 -91.497658)
		(end 176.64811 -91.497658)
		(width 0.127)
		(layer "In13.Cu")
		(net "FM_SLP_SUS_RSM_RST_N")
	)
	(segment
		(start 307.06822 -33.825688)
		(end 307.06822 -28.943808)
		(width 0.127)
		(layer "In13.Cu")
		(net "FM_SLP_SUS_RSM_RST_N")
	)
	(segment
		(start 170.94962 -110.569502)
		(end 170.94962 -105.075228)
		(width 0.127)
		(layer "In13.Cu")
		(net "FM_SLP_SUS_RSM_RST_N")
	)
	(segment
		(start 305.77282 -42.085768)
		(end 305.77282 -35.121088)
		(width 0.127)
		(layer "In13.Cu")
		(net "FM_SLP_SUS_RSM_RST_N")
	)
	(segment
		(start 171.46778 -98.44913)
		(end 170.815 -97.79635)
		(width 0.127)
		(layer "In13.Cu")
		(net "FM_SLP_SUS_RSM_RST_N")
	)
	(segment
		(start 170.94962 -105.075228)
		(end 170.94708 -105.072688)
		(width 0.127)
		(layer "In13.Cu")
		(net "FM_SLP_SUS_RSM_RST_N")
	)
	(segment
		(start 277.511256 -83.54695)
		(end 286.131 -74.927206)
		(width 0.127)
		(layer "In13.Cu")
		(net "FM_SLP_SUS_RSM_RST_N")
	)
	(segment
		(start 176.64811 -91.497658)
		(end 182.4736 -85.672168)
		(width 0.127)
		(layer "In13.Cu")
		(net "FM_SLP_SUS_RSM_RST_N")
	)
	(segment
		(start 170.815 -97.79635)
		(end 170.815 -93.614748)
		(width 0.127)
		(layer "In13.Cu")
		(net "FM_SLP_SUS_RSM_RST_N")
	)
	(segment
		(start 170.815 -93.614748)
		(end 172.93209 -91.497658)
		(width 0.127)
		(layer "In13.Cu")
		(net "FM_SLP_SUS_RSM_RST_N")
	)
	(segment
		(start 288.364168 -57.499758)
		(end 288.364168 -54.495954)
		(width 0.127)
		(layer "In13.Cu")
		(net "FM_SLP_SUS_RSM_RST_N")
	)
	(segment
		(start 286.131 -59.732926)
		(end 288.364168 -57.499758)
		(width 0.127)
		(layer "In13.Cu")
		(net "FM_SLP_SUS_RSM_RST_N")
	)
	(segment
		(start 291.601906 -50.010822)
		(end 296.02176 -45.590968)
		(width 0.127)
		(layer "In13.Cu")
		(net "FM_SLP_SUS_RSM_RST_N")
	)
	(segment
		(start 291.601906 -51.258216)
		(end 291.601906 -50.010822)
		(width 0.127)
		(layer "In13.Cu")
		(net "FM_SLP_SUS_RSM_RST_N")
	)
	(segment
		(start 288.364168 -54.495954)
		(end 291.601906 -51.258216)
		(width 0.127)
		(layer "In13.Cu")
		(net "FM_SLP_SUS_RSM_RST_N")
	)
	(segment
		(start 244.59946 -83.54695)
		(end 277.511256 -83.54695)
		(width 0.127)
		(layer "In13.Cu")
		(net "FM_SLP_SUS_RSM_RST_N")
	)
	(segment
		(start 171.355512 -110.975394)
		(end 170.94962 -110.569502)
		(width 0.127)
		(layer "In13.Cu")
		(net "FM_SLP_SUS_RSM_RST_N")
	)
	(segment
		(start 222.007684 -89.100914)
		(end 239.045496 -89.100914)
		(width 0.127)
		(layer "In13.Cu")
		(net "FM_SLP_SUS_RSM_RST_N")
	)
	(segment
		(start 308.33568 -27.676348)
		(end 311.3278 -27.676348)
		(width 0.127)
		(layer "In13.Cu")
		(net "FM_SLP_SUS_RSM_RST_N")
	)
	(segment
		(start 170.94708 -101.361748)
		(end 171.46778 -100.841048)
		(width 0.127)
		(layer "In13.Cu")
		(net "FM_SLP_SUS_RSM_RST_N")
	)
	(segment
		(start 296.02176 -45.590968)
		(end 302.26762 -45.590968)
		(width 0.127)
		(layer "In13.Cu")
		(net "FM_SLP_SUS_RSM_RST_N")
	)
	(segment
		(start 170.94708 -105.072688)
		(end 170.94708 -101.361748)
		(width 0.127)
		(layer "In13.Cu")
		(net "FM_SLP_SUS_RSM_RST_N")
	)
	(segment
		(start 182.4736 -85.672168)
		(end 218.578938 -85.672168)
		(width 0.127)
		(layer "In13.Cu")
		(net "FM_SLP_SUS_RSM_RST_N")
	)
	(segment
		(start 182.955692 -120.975374)
		(end 183.355742 -121.375424)
		(width 0.12954)
		(layer "F.Cu")
		(net "FM_SLPS4_PLD_N")
	)
	(via
		(at 325.93788 -121.249948)
		(size 0.508)
		(drill 0.254)
		(layers "F.Cu" "B.Cu")
		(net "FM_SLPS4_PLD_N")
	)
	(via
		(at 322.43268 -24.387048)
		(size 0.6604)
		(drill 0.3302)
		(layers "F.Cu" "B.Cu")
		(net "FM_SLPS4_PLD_N")
	)
	(via
		(at 183.355742 -121.375424)
		(size 0.4572)
		(drill 0.254)
		(layers "F.Cu" "B.Cu")
		(net "FM_SLPS4_PLD_N")
	)
	(via
		(at 320.62928 -24.387048)
		(size 0.508)
		(drill 0.254)
		(layers "F.Cu" "B.Cu")
		(net "FM_SLPS4_PLD_N")
	)
	(segment
		(start 322.91528 -24.387048)
		(end 323.815202 -25.28697)
		(width 0.12954)
		(layer "B.Cu")
		(net "FM_SLPS4_PLD_N")
	)
	(segment
		(start 323.815202 -25.28697)
		(end 324.19163 -25.28697)
		(width 0.12954)
		(layer "B.Cu")
		(net "FM_SLPS4_PLD_N")
	)
	(segment
		(start 320.62928 -24.387048)
		(end 322.43268 -24.387048)
		(width 0.12954)
		(layer "B.Cu")
		(net "FM_SLPS4_PLD_N")
	)
	(segment
		(start 322.43268 -24.387048)
		(end 322.91528 -24.387048)
		(width 0.12954)
		(layer "B.Cu")
		(net "FM_SLPS4_PLD_N")
	)
	(segment
		(start 320.62928 -24.387048)
		(end 320.56578 -24.323548)
		(width 0.127)
		(layer "In2.Cu")
		(net "FM_SLPS4_PLD_N")
	)
	(segment
		(start 318.9224 -25.364948)
		(end 318.9224 -34.889948)
		(width 0.127)
		(layer "In2.Cu")
		(net "FM_SLPS4_PLD_N")
	)
	(segment
		(start 322.19392 -69.733668)
		(end 325.67118 -73.210928)
		(width 0.127)
		(layer "In2.Cu")
		(net "FM_SLPS4_PLD_N")
	)
	(segment
		(start 319.9638 -24.323548)
		(end 318.9224 -25.364948)
		(width 0.127)
		(layer "In2.Cu")
		(net "FM_SLPS4_PLD_N")
	)
	(segment
		(start 322.19392 -67.363848)
		(end 322.19392 -69.733668)
		(width 0.127)
		(layer "In2.Cu")
		(net "FM_SLPS4_PLD_N")
	)
	(segment
		(start 323.989192 -61.736732)
		(end 322.53428 -63.191644)
		(width 0.127)
		(layer "In2.Cu")
		(net "FM_SLPS4_PLD_N")
	)
	(segment
		(start 325.67118 -73.210928)
		(end 325.67118 -120.983248)
		(width 0.127)
		(layer "In2.Cu")
		(net "FM_SLPS4_PLD_N")
	)
	(segment
		(start 323.0753 -39.042848)
		(end 323.13372 -39.042848)
		(width 0.127)
		(layer "In2.Cu")
		(net "FM_SLPS4_PLD_N")
	)
	(segment
		(start 323.989192 -56.157876)
		(end 323.989192 -61.736732)
		(width 0.127)
		(layer "In2.Cu")
		(net "FM_SLPS4_PLD_N")
	)
	(segment
		(start 320.56578 -24.323548)
		(end 319.9638 -24.323548)
		(width 0.127)
		(layer "In2.Cu")
		(net "FM_SLPS4_PLD_N")
	)
	(segment
		(start 322.53428 -63.191644)
		(end 322.53428 -67.023488)
		(width 0.127)
		(layer "In2.Cu")
		(net "FM_SLPS4_PLD_N")
	)
	(segment
		(start 326.04202 -50.302668)
		(end 325.27748 -51.067208)
		(width 0.127)
		(layer "In2.Cu")
		(net "FM_SLPS4_PLD_N")
	)
	(segment
		(start 325.67118 -120.983248)
		(end 325.93788 -121.249948)
		(width 0.127)
		(layer "In2.Cu")
		(net "FM_SLPS4_PLD_N")
	)
	(segment
		(start 318.9224 -34.889948)
		(end 323.0753 -39.042848)
		(width 0.127)
		(layer "In2.Cu")
		(net "FM_SLPS4_PLD_N")
	)
	(segment
		(start 323.13372 -39.042848)
		(end 325.36384 -41.272968)
		(width 0.127)
		(layer "In2.Cu")
		(net "FM_SLPS4_PLD_N")
	)
	(segment
		(start 325.27748 -51.067208)
		(end 325.27748 -54.869588)
		(width 0.127)
		(layer "In2.Cu")
		(net "FM_SLPS4_PLD_N")
	)
	(segment
		(start 325.27748 -54.869588)
		(end 323.989192 -56.157876)
		(width 0.127)
		(layer "In2.Cu")
		(net "FM_SLPS4_PLD_N")
	)
	(segment
		(start 325.36384 -41.272968)
		(end 325.36384 -45.799248)
		(width 0.127)
		(layer "In2.Cu")
		(net "FM_SLPS4_PLD_N")
	)
	(segment
		(start 322.53428 -67.023488)
		(end 322.19392 -67.363848)
		(width 0.127)
		(layer "In2.Cu")
		(net "FM_SLPS4_PLD_N")
	)
	(segment
		(start 325.36384 -45.799248)
		(end 326.04202 -46.477428)
		(width 0.127)
		(layer "In2.Cu")
		(net "FM_SLPS4_PLD_N")
	)
	(segment
		(start 326.04202 -46.477428)
		(end 326.04202 -50.302668)
		(width 0.127)
		(layer "In2.Cu")
		(net "FM_SLPS4_PLD_N")
	)
	(segment
		(start 242.859052 -124.437648)
		(end 244.753892 -126.332488)
		(width 0.127)
		(layer "In15.Cu")
		(net "FM_SLPS4_PLD_N")
	)
	(segment
		(start 183.355742 -121.375424)
		(end 183.355742 -122.05843)
		(width 0.127)
		(layer "In15.Cu")
		(net "FM_SLPS4_PLD_N")
	)
	(segment
		(start 251.092208 -124.234448)
		(end 284.11932 -124.234448)
		(width 0.127)
		(layer "In15.Cu")
		(net "FM_SLPS4_PLD_N")
	)
	(segment
		(start 220.97873 -123.19)
		(end 225.955352 -123.19)
		(width 0.127)
		(layer "In15.Cu")
		(net "FM_SLPS4_PLD_N")
	)
	(segment
		(start 183.355742 -122.05843)
		(end 187.4393 -126.141988)
		(width 0.127)
		(layer "In15.Cu")
		(net "FM_SLPS4_PLD_N")
	)
	(segment
		(start 198.598536 -129.121408)
		(end 199.996298 -129.121408)
		(width 0.127)
		(layer "In15.Cu")
		(net "FM_SLPS4_PLD_N")
	)
	(segment
		(start 284.11932 -124.234448)
		(end 285.68142 -122.672348)
		(width 0.127)
		(layer "In15.Cu")
		(net "FM_SLPS4_PLD_N")
	)
	(segment
		(start 232.917492 -123.269248)
		(end 237.646972 -123.269248)
		(width 0.127)
		(layer "In15.Cu")
		(net "FM_SLPS4_PLD_N")
	)
	(segment
		(start 227.69322 -124.041408)
		(end 229.0699 -122.664728)
		(width 0.127)
		(layer "In15.Cu")
		(net "FM_SLPS4_PLD_N")
	)
	(segment
		(start 238.815372 -124.437648)
		(end 242.859052 -124.437648)
		(width 0.127)
		(layer "In15.Cu")
		(net "FM_SLPS4_PLD_N")
	)
	(segment
		(start 213.641686 -127.962914)
		(end 216.205816 -127.962914)
		(width 0.127)
		(layer "In15.Cu")
		(net "FM_SLPS4_PLD_N")
	)
	(segment
		(start 244.753892 -126.332488)
		(end 248.994168 -126.332488)
		(width 0.127)
		(layer "In15.Cu")
		(net "FM_SLPS4_PLD_N")
	)
	(segment
		(start 206.10068 -128.158748)
		(end 213.445852 -128.158748)
		(width 0.127)
		(layer "In15.Cu")
		(net "FM_SLPS4_PLD_N")
	)
	(segment
		(start 194.42557 -129.936748)
		(end 197.783196 -129.936748)
		(width 0.127)
		(layer "In15.Cu")
		(net "FM_SLPS4_PLD_N")
	)
	(segment
		(start 229.0699 -122.664728)
		(end 232.312972 -122.664728)
		(width 0.127)
		(layer "In15.Cu")
		(net "FM_SLPS4_PLD_N")
	)
	(segment
		(start 232.312972 -122.664728)
		(end 232.917492 -123.269248)
		(width 0.127)
		(layer "In15.Cu")
		(net "FM_SLPS4_PLD_N")
	)
	(segment
		(start 226.80676 -124.041408)
		(end 227.69322 -124.041408)
		(width 0.127)
		(layer "In15.Cu")
		(net "FM_SLPS4_PLD_N")
	)
	(segment
		(start 324.51548 -122.672348)
		(end 325.93788 -121.249948)
		(width 0.127)
		(layer "In15.Cu")
		(net "FM_SLPS4_PLD_N")
	)
	(segment
		(start 216.205816 -127.962914)
		(end 220.97873 -123.19)
		(width 0.127)
		(layer "In15.Cu")
		(net "FM_SLPS4_PLD_N")
	)
	(segment
		(start 199.996298 -129.121408)
		(end 201.403458 -127.714248)
		(width 0.127)
		(layer "In15.Cu")
		(net "FM_SLPS4_PLD_N")
	)
	(segment
		(start 237.646972 -123.269248)
		(end 238.815372 -124.437648)
		(width 0.127)
		(layer "In15.Cu")
		(net "FM_SLPS4_PLD_N")
	)
	(segment
		(start 285.68142 -122.672348)
		(end 324.51548 -122.672348)
		(width 0.127)
		(layer "In15.Cu")
		(net "FM_SLPS4_PLD_N")
	)
	(segment
		(start 248.994168 -126.332488)
		(end 251.092208 -124.234448)
		(width 0.127)
		(layer "In15.Cu")
		(net "FM_SLPS4_PLD_N")
	)
	(segment
		(start 194.206876 -129.718054)
		(end 194.42557 -129.936748)
		(width 0.127)
		(layer "In15.Cu")
		(net "FM_SLPS4_PLD_N")
	)
	(segment
		(start 213.445852 -128.158748)
		(end 213.641686 -127.962914)
		(width 0.127)
		(layer "In15.Cu")
		(net "FM_SLPS4_PLD_N")
	)
	(segment
		(start 197.783196 -129.936748)
		(end 198.598536 -129.121408)
		(width 0.127)
		(layer "In15.Cu")
		(net "FM_SLPS4_PLD_N")
	)
	(segment
		(start 201.403458 -127.714248)
		(end 205.65618 -127.714248)
		(width 0.127)
		(layer "In15.Cu")
		(net "FM_SLPS4_PLD_N")
	)
	(segment
		(start 193.0527 -129.718054)
		(end 194.206876 -129.718054)
		(width 0.127)
		(layer "In15.Cu")
		(net "FM_SLPS4_PLD_N")
	)
	(segment
		(start 189.476634 -126.141988)
		(end 193.0527 -129.718054)
		(width 0.127)
		(layer "In15.Cu")
		(net "FM_SLPS4_PLD_N")
	)
	(segment
		(start 187.4393 -126.141988)
		(end 189.476634 -126.141988)
		(width 0.127)
		(layer "In15.Cu")
		(net "FM_SLPS4_PLD_N")
	)
	(segment
		(start 205.65618 -127.714248)
		(end 206.10068 -128.158748)
		(width 0.127)
		(layer "In15.Cu")
		(net "FM_SLPS4_PLD_N")
	)
	(segment
		(start 225.955352 -123.19)
		(end 226.80676 -124.041408)
		(width 0.127)
		(layer "In15.Cu")
		(net "FM_SLPS4_PLD_N")
	)
	(segment
		(start 182.955692 -116.175536)
		(end 183.355742 -116.575586)
		(width 0.12954)
		(layer "F.Cu")
		(net "FM_SLPS3_PLD_N")
	)
	(via
		(at 315.21654 -28.138628)
		(size 0.508)
		(drill 0.254)
		(layers "F.Cu" "B.Cu")
		(net "FM_SLPS3_PLD_N")
	)
	(via
		(at 183.355742 -116.575586)
		(size 0.4572)
		(drill 0.254)
		(layers "F.Cu" "B.Cu")
		(net "FM_SLPS3_PLD_N")
	)
	(via
		(at 324.15988 -121.249948)
		(size 0.508)
		(drill 0.254)
		(layers "F.Cu" "B.Cu")
		(net "FM_SLPS3_PLD_N")
	)
	(segment
		(start 315.21654 -28.138628)
		(end 314.76696 -28.138628)
		(width 0.12954)
		(layer "B.Cu")
		(net "FM_SLPS3_PLD_N")
	)
	(segment
		(start 314.473336 -29.100526)
		(end 314.963556 -30.283658)
		(width 0.12954)
		(layer "B.Cu")
		(net "FM_SLPS3_PLD_N")
	)
	(segment
		(start 320.594482 -35.573208)
		(end 320.923666 -35.902392)
		(width 0.12954)
		(layer "B.Cu")
		(net "FM_SLPS3_PLD_N")
	)
	(segment
		(start 318.247776 -33.567878)
		(end 318.247776 -34.008568)
		(width 0.12954)
		(layer "B.Cu")
		(net "FM_SLPS3_PLD_N")
	)
	(segment
		(start 314.963556 -30.283658)
		(end 318.247776 -33.567878)
		(width 0.12954)
		(layer "B.Cu")
		(net "FM_SLPS3_PLD_N")
	)
	(segment
		(start 319.812416 -35.573208)
		(end 320.594482 -35.573208)
		(width 0.12954)
		(layer "B.Cu")
		(net "FM_SLPS3_PLD_N")
	)
	(segment
		(start 314.76696 -28.138628)
		(end 314.473336 -28.432252)
		(width 0.12954)
		(layer "B.Cu")
		(net "FM_SLPS3_PLD_N")
	)
	(segment
		(start 314.473336 -28.432252)
		(end 314.473336 -29.100526)
		(width 0.12954)
		(layer "B.Cu")
		(net "FM_SLPS3_PLD_N")
	)
	(segment
		(start 318.247776 -34.008568)
		(end 319.812416 -35.573208)
		(width 0.12954)
		(layer "B.Cu")
		(net "FM_SLPS3_PLD_N")
	)
	(segment
		(start 315.65088 -27.015948)
		(end 315.21654 -27.450288)
		(width 0.127)
		(layer "In2.Cu")
		(net "FM_SLPS3_PLD_N")
	)
	(segment
		(start 317.27648 -32.835088)
		(end 316.34811 -31.906718)
		(width 0.127)
		(layer "In2.Cu")
		(net "FM_SLPS3_PLD_N")
	)
	(segment
		(start 316.41288 -27.015948)
		(end 315.65088 -27.015948)
		(width 0.127)
		(layer "In2.Cu")
		(net "FM_SLPS3_PLD_N")
	)
	(segment
		(start 320.79692 -68.163948)
		(end 317.27648 -64.643508)
		(width 0.127)
		(layer "In2.Cu")
		(net "FM_SLPS3_PLD_N")
	)
	(segment
		(start 324.1802 -73.777348)
		(end 320.79692 -70.394068)
		(width 0.127)
		(layer "In2.Cu")
		(net "FM_SLPS3_PLD_N")
	)
	(segment
		(start 317.27648 -64.643508)
		(end 317.27648 -32.835088)
		(width 0.127)
		(layer "In2.Cu")
		(net "FM_SLPS3_PLD_N")
	)
	(segment
		(start 315.21654 -27.450288)
		(end 315.21654 -28.138628)
		(width 0.127)
		(layer "In2.Cu")
		(net "FM_SLPS3_PLD_N")
	)
	(segment
		(start 324.15988 -121.249948)
		(end 324.1802 -121.229628)
		(width 0.127)
		(layer "In2.Cu")
		(net "FM_SLPS3_PLD_N")
	)
	(segment
		(start 316.34811 -30.382718)
		(end 316.79388 -29.936948)
		(width 0.127)
		(layer "In2.Cu")
		(net "FM_SLPS3_PLD_N")
	)
	(segment
		(start 316.79388 -27.396948)
		(end 316.41288 -27.015948)
		(width 0.127)
		(layer "In2.Cu")
		(net "FM_SLPS3_PLD_N")
	)
	(segment
		(start 316.34811 -31.906718)
		(end 316.34811 -30.382718)
		(width 0.127)
		(layer "In2.Cu")
		(net "FM_SLPS3_PLD_N")
	)
	(segment
		(start 324.1802 -121.229628)
		(end 324.1802 -73.777348)
		(width 0.127)
		(layer "In2.Cu")
		(net "FM_SLPS3_PLD_N")
	)
	(segment
		(start 320.79692 -70.394068)
		(end 320.79692 -68.163948)
		(width 0.127)
		(layer "In2.Cu")
		(net "FM_SLPS3_PLD_N")
	)
	(segment
		(start 316.79388 -29.936948)
		(end 316.79388 -27.396948)
		(width 0.127)
		(layer "In2.Cu")
		(net "FM_SLPS3_PLD_N")
	)
	(segment
		(start 193.506344 -124.149612)
		(end 194.13728 -124.780548)
		(width 0.127)
		(layer "In15.Cu")
		(net "FM_SLPS3_PLD_N")
	)
	(segment
		(start 322.07708 -121.783348)
		(end 323.62648 -121.783348)
		(width 0.127)
		(layer "In15.Cu")
		(net "FM_SLPS3_PLD_N")
	)
	(segment
		(start 183.76265 -117.538246)
		(end 183.992774 -117.76837)
		(width 0.127)
		(layer "In15.Cu")
		(net "FM_SLPS3_PLD_N")
	)
	(segment
		(start 186.487308 -117.5512)
		(end 188.264292 -118.287292)
		(width 0.127)
		(layer "In15.Cu")
		(net "FM_SLPS3_PLD_N")
	)
	(segment
		(start 185.36285 -117.07495)
		(end 185.459116 -116.978684)
		(width 0.127)
		(layer "In15.Cu")
		(net "FM_SLPS3_PLD_N")
	)
	(segment
		(start 192.326768 -121.5644)
		(end 193.506344 -122.743976)
		(width 0.127)
		(layer "In15.Cu")
		(net "FM_SLPS3_PLD_N")
	)
	(segment
		(start 320.60388 -120.310148)
		(end 322.07708 -121.783348)
		(width 0.127)
		(layer "In15.Cu")
		(net "FM_SLPS3_PLD_N")
	)
	(segment
		(start 242.56492 -121.821448)
		(end 245.54688 -124.803408)
		(width 0.127)
		(layer "In15.Cu")
		(net "FM_SLPS3_PLD_N")
	)
	(segment
		(start 220.762322 -119.342408)
		(end 220.789246 -119.342408)
		(width 0.127)
		(layer "In15.Cu")
		(net "FM_SLPS3_PLD_N")
	)
	(segment
		(start 323.62648 -121.783348)
		(end 324.15988 -121.249948)
		(width 0.127)
		(layer "In15.Cu")
		(net "FM_SLPS3_PLD_N")
	)
	(segment
		(start 234.42168 -121.821448)
		(end 242.56492 -121.821448)
		(width 0.127)
		(layer "In15.Cu")
		(net "FM_SLPS3_PLD_N")
	)
	(segment
		(start 220.789246 -119.342408)
		(end 221.063566 -119.068088)
		(width 0.127)
		(layer "In15.Cu")
		(net "FM_SLPS3_PLD_N")
	)
	(segment
		(start 221.063566 -119.068088)
		(end 231.66832 -119.068088)
		(width 0.127)
		(layer "In15.Cu")
		(net "FM_SLPS3_PLD_N")
	)
	(segment
		(start 188.264292 -118.287292)
		(end 191.5414 -121.5644)
		(width 0.127)
		(layer "In15.Cu")
		(net "FM_SLPS3_PLD_N")
	)
	(segment
		(start 183.355742 -116.575586)
		(end 183.355742 -116.76761)
		(width 0.127)
		(layer "In15.Cu")
		(net "FM_SLPS3_PLD_N")
	)
	(segment
		(start 208.28508 -123.459748)
		(end 216.644982 -123.459748)
		(width 0.127)
		(layer "In15.Cu")
		(net "FM_SLPS3_PLD_N")
	)
	(segment
		(start 282.48737 -122.786648)
		(end 284.96387 -120.310148)
		(width 0.127)
		(layer "In15.Cu")
		(net "FM_SLPS3_PLD_N")
	)
	(segment
		(start 284.96387 -120.310148)
		(end 320.60388 -120.310148)
		(width 0.127)
		(layer "In15.Cu")
		(net "FM_SLPS3_PLD_N")
	)
	(segment
		(start 183.355742 -116.76761)
		(end 183.76265 -117.174518)
		(width 0.127)
		(layer "In15.Cu")
		(net "FM_SLPS3_PLD_N")
	)
	(segment
		(start 245.54688 -124.803408)
		(end 248.252742 -124.803408)
		(width 0.127)
		(layer "In15.Cu")
		(net "FM_SLPS3_PLD_N")
	)
	(segment
		(start 216.644982 -123.459748)
		(end 220.762322 -119.342408)
		(width 0.127)
		(layer "In15.Cu")
		(net "FM_SLPS3_PLD_N")
	)
	(segment
		(start 185.36285 -117.531896)
		(end 185.36285 -117.07495)
		(width 0.127)
		(layer "In15.Cu")
		(net "FM_SLPS3_PLD_N")
	)
	(segment
		(start 206.96428 -124.780548)
		(end 208.28508 -123.459748)
		(width 0.127)
		(layer "In15.Cu")
		(net "FM_SLPS3_PLD_N")
	)
	(segment
		(start 185.914792 -116.978684)
		(end 186.487308 -117.5512)
		(width 0.127)
		(layer "In15.Cu")
		(net "FM_SLPS3_PLD_N")
	)
	(segment
		(start 185.126376 -117.76837)
		(end 185.36285 -117.531896)
		(width 0.127)
		(layer "In15.Cu")
		(net "FM_SLPS3_PLD_N")
	)
	(segment
		(start 185.459116 -116.978684)
		(end 185.914792 -116.978684)
		(width 0.127)
		(layer "In15.Cu")
		(net "FM_SLPS3_PLD_N")
	)
	(segment
		(start 250.269502 -122.786648)
		(end 282.48737 -122.786648)
		(width 0.127)
		(layer "In15.Cu")
		(net "FM_SLPS3_PLD_N")
	)
	(segment
		(start 248.252742 -124.803408)
		(end 250.269502 -122.786648)
		(width 0.127)
		(layer "In15.Cu")
		(net "FM_SLPS3_PLD_N")
	)
	(segment
		(start 194.13728 -124.780548)
		(end 206.96428 -124.780548)
		(width 0.127)
		(layer "In15.Cu")
		(net "FM_SLPS3_PLD_N")
	)
	(segment
		(start 183.76265 -117.174518)
		(end 183.76265 -117.538246)
		(width 0.127)
		(layer "In15.Cu")
		(net "FM_SLPS3_PLD_N")
	)
	(segment
		(start 191.5414 -121.5644)
		(end 192.326768 -121.5644)
		(width 0.127)
		(layer "In15.Cu")
		(net "FM_SLPS3_PLD_N")
	)
	(segment
		(start 231.66832 -119.068088)
		(end 234.42168 -121.821448)
		(width 0.127)
		(layer "In15.Cu")
		(net "FM_SLPS3_PLD_N")
	)
	(segment
		(start 183.992774 -117.76837)
		(end 185.126376 -117.76837)
		(width 0.127)
		(layer "In15.Cu")
		(net "FM_SLPS3_PLD_N")
	)
	(segment
		(start 193.506344 -122.743976)
		(end 193.506344 -124.149612)
		(width 0.127)
		(layer "In15.Cu")
		(net "FM_SLPS3_PLD_N")
	)
	(segment
		(start 190.550292 -36.433252)
		(end 190.19774 -36.0807)
		(width 0.12954)
		(layer "F.Cu")
		(net "FM_SCM_PRSNT1_R_N")
	)
	(segment
		(start 191.4144 -36.433252)
		(end 190.550292 -36.433252)
		(width 0.12954)
		(layer "F.Cu")
		(net "FM_SCM_PRSNT1_R_N")
	)
	(segment
		(start 192.859406 -36.433252)
		(end 191.4144 -36.433252)
		(width 0.12954)
		(layer "F.Cu")
		(net "FM_SCM_PRSNT1_R_N")
	)
	(via
		(at 191.4144 -36.433252)
		(size 0.762)
		(drill 0.381)
		(layers "F.Cu" "B.Cu")
		(net "FM_SCM_PRSNT1_R_N")
	)
	(segment
		(start 186.95924 -36.965128)
		(end 188.906912 -35.017456)
		(width 0.12954)
		(layer "F.Cu")
		(net "FM_SCM_PRSNT1_N")
	)
	(segment
		(start 188.906912 -35.017456)
		(end 189.40018 -35.017456)
		(width 0.12954)
		(layer "F.Cu")
		(net "FM_SCM_PRSNT1_N")
	)
	(segment
		(start 137.547096 -13.600176)
		(end 137.547096 -13.599668)
		(width 0.12954)
		(layer "F.Cu")
		(net "FM_SCM_PRSNT1_N")
	)
	(segment
		(start 137.681462 -12.05357)
		(end 137.6807 -12.052808)
		(width 0.12954)
		(layer "F.Cu")
		(net "FM_SCM_PRSNT1_N")
	)
	(segment
		(start 137.681462 -13.465302)
		(end 137.681462 -12.05357)
		(width 0.12954)
		(layer "F.Cu")
		(net "FM_SCM_PRSNT1_N")
	)
	(segment
		(start 189.40018 -35.017456)
		(end 189.39764 -35.019996)
		(width 0.12954)
		(layer "F.Cu")
		(net "FM_SCM_PRSNT1_N")
	)
	(segment
		(start 137.547096 -13.599668)
		(end 137.681462 -13.465302)
		(width 0.12954)
		(layer "F.Cu")
		(net "FM_SCM_PRSNT1_N")
	)
	(segment
		(start 189.39764 -35.019996)
		(end 189.39764 -36.0807)
		(width 0.12954)
		(layer "F.Cu")
		(net "FM_SCM_PRSNT1_N")
	)
	(via
		(at 186.95924 -36.965128)
		(size 0.508)
		(drill 0.254)
		(layers "F.Cu" "B.Cu")
		(net "FM_SCM_PRSNT1_N")
	)
	(via
		(at 137.6807 -12.052808)
		(size 0.508)
		(drill 0.254)
		(layers "F.Cu" "B.Cu")
		(net "FM_SCM_PRSNT1_N")
	)
	(via
		(at 146.78152 -19.162268)
		(size 0.508)
		(drill 0.254)
		(layers "F.Cu" "B.Cu")
		(net "FM_SCM_PRSNT1_N")
	)
	(via
		(at 147.08632 -30.328108)
		(size 0.508)
		(drill 0.254)
		(layers "F.Cu" "B.Cu")
		(net "FM_SCM_PRSNT1_N")
	)
	(segment
		(start 147.08632 -19.467068)
		(end 146.78152 -19.162268)
		(width 0.127)
		(layer "In2.Cu")
		(net "FM_SCM_PRSNT1_N")
	)
	(segment
		(start 147.08632 -30.328108)
		(end 147.08632 -19.467068)
		(width 0.127)
		(layer "In2.Cu")
		(net "FM_SCM_PRSNT1_N")
	)
	(segment
		(start 160.86836 -29.096208)
		(end 164.8079 -33.035748)
		(width 0.127)
		(layer "In4.Cu")
		(net "FM_SCM_PRSNT1_N")
	)
	(segment
		(start 147.06092 -14.021308)
		(end 139.6492 -14.021308)
		(width 0.127)
		(layer "In4.Cu")
		(net "FM_SCM_PRSNT1_N")
	)
	(segment
		(start 164.8079 -33.035748)
		(end 170.1165 -33.035748)
		(width 0.127)
		(layer "In4.Cu")
		(net "FM_SCM_PRSNT1_N")
	)
	(segment
		(start 147.08632 -30.328108)
		(end 148.31822 -29.096208)
		(width 0.127)
		(layer "In4.Cu")
		(net "FM_SCM_PRSNT1_N")
	)
	(segment
		(start 186.2328 -37.691568)
		(end 186.95924 -36.965128)
		(width 0.127)
		(layer "In4.Cu")
		(net "FM_SCM_PRSNT1_N")
	)
	(segment
		(start 148.31822 -29.096208)
		(end 160.86836 -29.096208)
		(width 0.127)
		(layer "In4.Cu")
		(net "FM_SCM_PRSNT1_N")
	)
	(segment
		(start 147.9677 -14.928088)
		(end 147.06092 -14.021308)
		(width 0.127)
		(layer "In4.Cu")
		(net "FM_SCM_PRSNT1_N")
	)
	(segment
		(start 170.1165 -33.035748)
		(end 174.77232 -37.691568)
		(width 0.127)
		(layer "In4.Cu")
		(net "FM_SCM_PRSNT1_N")
	)
	(segment
		(start 174.77232 -37.691568)
		(end 186.2328 -37.691568)
		(width 0.127)
		(layer "In4.Cu")
		(net "FM_SCM_PRSNT1_N")
	)
	(segment
		(start 146.78152 -18.14068)
		(end 147.9677 -16.9545)
		(width 0.127)
		(layer "In4.Cu")
		(net "FM_SCM_PRSNT1_N")
	)
	(segment
		(start 146.78152 -19.162268)
		(end 146.78152 -18.14068)
		(width 0.127)
		(layer "In4.Cu")
		(net "FM_SCM_PRSNT1_N")
	)
	(segment
		(start 139.6492 -14.021308)
		(end 137.6807 -12.052808)
		(width 0.127)
		(layer "In4.Cu")
		(net "FM_SCM_PRSNT1_N")
	)
	(segment
		(start 147.9677 -16.9545)
		(end 147.9677 -14.928088)
		(width 0.127)
		(layer "In4.Cu")
		(net "FM_SCM_PRSNT1_N")
	)
	(segment
		(start 102.822248 -272.103342)
		(end 102.821994 -272.103596)
		(width 0.12954)
		(layer "F.Cu")
		(net "FM_S3M_CPU1_LVC1_GPIO_4")
	)
	(segment
		(start 102.821994 -272.103596)
		(end 102.821994 -272.639282)
		(width 0.12954)
		(layer "F.Cu")
		(net "FM_S3M_CPU1_LVC1_GPIO_4")
	)
	(via
		(at 73.12025 -265.283442)
		(size 0.6604)
		(drill 0.3302)
		(layers "F.Cu" "B.Cu")
		(net "FM_S3M_CPU1_LVC1_GPIO_4")
	)
	(via
		(at 102.821994 -272.639282)
		(size 0.4572)
		(drill 0.2032)
		(layers "F.Cu" "B.Cu")
		(net "FM_S3M_CPU1_LVC1_GPIO_4")
	)
	(segment
		(start 80.337152 -272.500344)
		(end 73.12025 -265.283442)
		(width 0.12954)
		(layer "B.Cu")
		(net "FM_S3M_CPU1_LVC1_GPIO_4")
	)
	(segment
		(start 46.679358 -253.06655)
		(end 46.308518 -252.69571)
		(width 0.12954)
		(layer "B.Cu")
		(net "FM_S3M_CPU1_LVC1_GPIO_4")
	)
	(segment
		(start 56.796178 -247.92813)
		(end 55.681118 -249.04319)
		(width 0.12954)
		(layer "B.Cu")
		(net "FM_S3M_CPU1_LVC1_GPIO_4")
	)
	(segment
		(start 102.634796 -272.314924)
		(end 102.620064 -272.32356)
		(width 0.0889)
		(layer "B.Cu")
		(net "FM_S3M_CPU1_LVC1_GPIO_4")
	)
	(segment
		(start 46.839378 -194.47129)
		(end 47.650908 -193.65976)
		(width 0.12954)
		(layer "B.Cu")
		(net "FM_S3M_CPU1_LVC1_GPIO_4")
	)
	(segment
		(start 103.134668 -272.639282)
		(end 103.192072 -272.581878)
		(width 0.0889)
		(layer "B.Cu")
		(net "FM_S3M_CPU1_LVC1_GPIO_4")
	)
	(segment
		(start 55.681118 -249.99315)
		(end 55.495698 -250.17857)
		(width 0.12954)
		(layer "B.Cu")
		(net "FM_S3M_CPU1_LVC1_GPIO_4")
	)
	(segment
		(start 100.755196 -272.314924)
		(end 100.740464 -272.32356)
		(width 0.0889)
		(layer "B.Cu")
		(net "FM_S3M_CPU1_LVC1_GPIO_4")
	)
	(segment
		(start 89.862406 -272.32102)
		(end 89.851992 -272.314924)
		(width 0.0889)
		(layer "B.Cu")
		(net "FM_S3M_CPU1_LVC1_GPIO_4")
	)
	(segment
		(start 87.58047 -272.50009)
		(end 82.025998 -272.50009)
		(width 0.12954)
		(layer "B.Cu")
		(net "FM_S3M_CPU1_LVC1_GPIO_4")
	)
	(segment
		(start 59.356498 -247.92813)
		(end 56.796178 -247.92813)
		(width 0.12954)
		(layer "B.Cu")
		(net "FM_S3M_CPU1_LVC1_GPIO_4")
	)
	(segment
		(start 101.694996 -272.314924)
		(end 101.680264 -272.32356)
		(width 0.0889)
		(layer "B.Cu")
		(net "FM_S3M_CPU1_LVC1_GPIO_4")
	)
	(segment
		(start 95.116396 -272.314924)
		(end 95.101664 -272.32356)
		(width 0.0889)
		(layer "B.Cu")
		(net "FM_S3M_CPU1_LVC1_GPIO_4")
	)
	(segment
		(start 96.99625 -272.314924)
		(end 96.985836 -272.32102)
		(width 0.0889)
		(layer "B.Cu")
		(net "FM_S3M_CPU1_LVC1_GPIO_4")
	)
	(segment
		(start 92.296996 -272.314924)
		(end 92.282264 -272.32356)
		(width 0.0889)
		(layer "B.Cu")
		(net "FM_S3M_CPU1_LVC1_GPIO_4")
	)
	(segment
		(start 87.824056 -272.50644)
		(end 87.58682 -272.50644)
		(width 0.0889)
		(layer "B.Cu")
		(net "FM_S3M_CPU1_LVC1_GPIO_4")
	)
	(segment
		(start 46.308518 -195.47713)
		(end 46.839378 -194.94627)
		(width 0.12954)
		(layer "B.Cu")
		(net "FM_S3M_CPU1_LVC1_GPIO_4")
	)
	(segment
		(start 69.425312 -248.95429)
		(end 68.851272 -248.38025)
		(width 0.12954)
		(layer "B.Cu")
		(net "FM_S3M_CPU1_LVC1_GPIO_4")
	)
	(segment
		(start 93.236796 -272.314924)
		(end 93.222064 -272.32356)
		(width 0.0889)
		(layer "B.Cu")
		(net "FM_S3M_CPU1_LVC1_GPIO_4")
	)
	(segment
		(start 90.80246 -272.32102)
		(end 90.792046 -272.314924)
		(width 0.0889)
		(layer "B.Cu")
		(net "FM_S3M_CPU1_LVC1_GPIO_4")
	)
	(segment
		(start 68.851272 -248.38025)
		(end 62.892432 -248.38025)
		(width 0.12954)
		(layer "B.Cu")
		(net "FM_S3M_CPU1_LVC1_GPIO_4")
	)
	(segment
		(start 62.328552 -247.81637)
		(end 59.468258 -247.81637)
		(width 0.12954)
		(layer "B.Cu")
		(net "FM_S3M_CPU1_LVC1_GPIO_4")
	)
	(segment
		(start 94.176596 -272.314924)
		(end 94.161864 -272.32356)
		(width 0.0889)
		(layer "B.Cu")
		(net "FM_S3M_CPU1_LVC1_GPIO_4")
	)
	(segment
		(start 55.681118 -249.04319)
		(end 55.681118 -249.99315)
		(width 0.12954)
		(layer "B.Cu")
		(net "FM_S3M_CPU1_LVC1_GPIO_4")
	)
	(segment
		(start 97.38106 -272.32102)
		(end 97.370646 -272.314924)
		(width 0.0889)
		(layer "B.Cu")
		(net "FM_S3M_CPU1_LVC1_GPIO_4")
	)
	(segment
		(start 55.495698 -250.17857)
		(end 55.495698 -251.39777)
		(width 0.12954)
		(layer "B.Cu")
		(net "FM_S3M_CPU1_LVC1_GPIO_4")
	)
	(segment
		(start 69.425312 -261.588504)
		(end 69.425312 -248.95429)
		(width 0.12954)
		(layer "B.Cu")
		(net "FM_S3M_CPU1_LVC1_GPIO_4")
	)
	(segment
		(start 102.821994 -272.639282)
		(end 103.134668 -272.639282)
		(width 0.0889)
		(layer "B.Cu")
		(net "FM_S3M_CPU1_LVC1_GPIO_4")
	)
	(segment
		(start 49.008538 -253.06655)
		(end 46.679358 -253.06655)
		(width 0.12954)
		(layer "B.Cu")
		(net "FM_S3M_CPU1_LVC1_GPIO_4")
	)
	(segment
		(start 62.892432 -248.38025)
		(end 62.328552 -247.81637)
		(width 0.12954)
		(layer "B.Cu")
		(net "FM_S3M_CPU1_LVC1_GPIO_4")
	)
	(segment
		(start 99.815396 -272.314924)
		(end 99.800664 -272.32356)
		(width 0.0889)
		(layer "B.Cu")
		(net "FM_S3M_CPU1_LVC1_GPIO_4")
	)
	(segment
		(start 87.58682 -272.50644)
		(end 87.58047 -272.50009)
		(width 0.12954)
		(layer "B.Cu")
		(net "FM_S3M_CPU1_LVC1_GPIO_4")
	)
	(segment
		(start 50.113438 -254.17145)
		(end 49.008538 -253.06655)
		(width 0.12954)
		(layer "B.Cu")
		(net "FM_S3M_CPU1_LVC1_GPIO_4")
	)
	(segment
		(start 46.308518 -252.69571)
		(end 46.308518 -195.47713)
		(width 0.12954)
		(layer "B.Cu")
		(net "FM_S3M_CPU1_LVC1_GPIO_4")
	)
	(segment
		(start 82.025744 -272.500344)
		(end 80.337152 -272.500344)
		(width 0.12954)
		(layer "B.Cu")
		(net "FM_S3M_CPU1_LVC1_GPIO_4")
	)
	(segment
		(start 82.025998 -272.50009)
		(end 82.025744 -272.500344)
		(width 0.12954)
		(layer "B.Cu")
		(net "FM_S3M_CPU1_LVC1_GPIO_4")
	)
	(segment
		(start 52.722018 -254.17145)
		(end 50.113438 -254.17145)
		(width 0.12954)
		(layer "B.Cu")
		(net "FM_S3M_CPU1_LVC1_GPIO_4")
	)
	(segment
		(start 98.875596 -272.314924)
		(end 98.860864 -272.32356)
		(width 0.0889)
		(layer "B.Cu")
		(net "FM_S3M_CPU1_LVC1_GPIO_4")
	)
	(segment
		(start 55.495698 -251.39777)
		(end 52.722018 -254.17145)
		(width 0.12954)
		(layer "B.Cu")
		(net "FM_S3M_CPU1_LVC1_GPIO_4")
	)
	(segment
		(start 89.477596 -272.314924)
		(end 89.467182 -272.32102)
		(width 0.0889)
		(layer "B.Cu")
		(net "FM_S3M_CPU1_LVC1_GPIO_4")
	)
	(segment
		(start 96.056196 -272.314924)
		(end 96.041464 -272.32356)
		(width 0.0889)
		(layer "B.Cu")
		(net "FM_S3M_CPU1_LVC1_GPIO_4")
	)
	(segment
		(start 59.468258 -247.81637)
		(end 59.356498 -247.92813)
		(width 0.12954)
		(layer "B.Cu")
		(net "FM_S3M_CPU1_LVC1_GPIO_4")
	)
	(segment
		(start 46.839378 -194.94627)
		(end 46.839378 -194.47129)
		(width 0.12954)
		(layer "B.Cu")
		(net "FM_S3M_CPU1_LVC1_GPIO_4")
	)
	(segment
		(start 73.12025 -265.283442)
		(end 69.425312 -261.588504)
		(width 0.12954)
		(layer "B.Cu")
		(net "FM_S3M_CPU1_LVC1_GPIO_4")
	)
	(arc
		(start 90.41765 -272.314924)
		(mid 90.140837 -272.39076)
		(end 89.862406 -272.32102)
		(width 0.0889)
		(layer "B.Cu")
		(net "FM_S3M_CPU1_LVC1_GPIO_4")
	)
	(arc
		(start 89.851992 -272.314924)
		(mid 89.664794 -272.264781)
		(end 89.477596 -272.314924)
		(width 0.0889)
		(layer "B.Cu")
		(net "FM_S3M_CPU1_LVC1_GPIO_4")
	)
	(arc
		(start 93.611192 -272.314924)
		(mid 93.423994 -272.264781)
		(end 93.236796 -272.314924)
		(width 0.0889)
		(layer "B.Cu")
		(net "FM_S3M_CPU1_LVC1_GPIO_4")
	)
	(arc
		(start 97.370646 -272.314924)
		(mid 97.183448 -272.264781)
		(end 96.99625 -272.314924)
		(width 0.0889)
		(layer "B.Cu")
		(net "FM_S3M_CPU1_LVC1_GPIO_4")
	)
	(arc
		(start 101.129592 -272.314924)
		(mid 100.942394 -272.264781)
		(end 100.755196 -272.314924)
		(width 0.0889)
		(layer "B.Cu")
		(net "FM_S3M_CPU1_LVC1_GPIO_4")
	)
	(arc
		(start 94.161864 -272.32356)
		(mid 93.885423 -272.390726)
		(end 93.611192 -272.314924)
		(width 0.0889)
		(layer "B.Cu")
		(net "FM_S3M_CPU1_LVC1_GPIO_4")
	)
	(arc
		(start 99.249992 -272.314924)
		(mid 99.062794 -272.264781)
		(end 98.875596 -272.314924)
		(width 0.0889)
		(layer "B.Cu")
		(net "FM_S3M_CPU1_LVC1_GPIO_4")
	)
	(arc
		(start 91.731592 -272.314924)
		(mid 91.544394 -272.264781)
		(end 91.357196 -272.314924)
		(width 0.0889)
		(layer "B.Cu")
		(net "FM_S3M_CPU1_LVC1_GPIO_4")
	)
	(arc
		(start 90.792046 -272.314924)
		(mid 90.604848 -272.264781)
		(end 90.41765 -272.314924)
		(width 0.0889)
		(layer "B.Cu")
		(net "FM_S3M_CPU1_LVC1_GPIO_4")
	)
	(arc
		(start 88.53805 -272.314924)
		(mid 88.193676 -272.457751)
		(end 87.824056 -272.50644)
		(width 0.0889)
		(layer "B.Cu")
		(net "FM_S3M_CPU1_LVC1_GPIO_4")
	)
	(arc
		(start 100.189792 -272.314924)
		(mid 100.002594 -272.264781)
		(end 99.815396 -272.314924)
		(width 0.0889)
		(layer "B.Cu")
		(net "FM_S3M_CPU1_LVC1_GPIO_4")
	)
	(arc
		(start 93.222064 -272.32356)
		(mid 92.945623 -272.390726)
		(end 92.671392 -272.314924)
		(width 0.0889)
		(layer "B.Cu")
		(net "FM_S3M_CPU1_LVC1_GPIO_4")
	)
	(arc
		(start 96.430592 -272.314924)
		(mid 96.243394 -272.264781)
		(end 96.056196 -272.314924)
		(width 0.0889)
		(layer "B.Cu")
		(net "FM_S3M_CPU1_LVC1_GPIO_4")
	)
	(arc
		(start 92.671392 -272.314924)
		(mid 92.484194 -272.264781)
		(end 92.296996 -272.314924)
		(width 0.0889)
		(layer "B.Cu")
		(net "FM_S3M_CPU1_LVC1_GPIO_4")
	)
	(arc
		(start 98.310192 -272.314924)
		(mid 98.122994 -272.264781)
		(end 97.935796 -272.314924)
		(width 0.0889)
		(layer "B.Cu")
		(net "FM_S3M_CPU1_LVC1_GPIO_4")
	)
	(arc
		(start 91.357196 -272.314924)
		(mid 91.080637 -272.390633)
		(end 90.80246 -272.32102)
		(width 0.0889)
		(layer "B.Cu")
		(net "FM_S3M_CPU1_LVC1_GPIO_4")
	)
	(arc
		(start 101.680264 -272.32356)
		(mid 101.403823 -272.390726)
		(end 101.129592 -272.314924)
		(width 0.0889)
		(layer "B.Cu")
		(net "FM_S3M_CPU1_LVC1_GPIO_4")
	)
	(arc
		(start 97.935796 -272.314924)
		(mid 97.659237 -272.390633)
		(end 97.38106 -272.32102)
		(width 0.0889)
		(layer "B.Cu")
		(net "FM_S3M_CPU1_LVC1_GPIO_4")
	)
	(arc
		(start 95.101664 -272.32356)
		(mid 94.825223 -272.390726)
		(end 94.550992 -272.314924)
		(width 0.0889)
		(layer "B.Cu")
		(net "FM_S3M_CPU1_LVC1_GPIO_4")
	)
	(arc
		(start 95.490792 -272.314924)
		(mid 95.303594 -272.264781)
		(end 95.116396 -272.314924)
		(width 0.0889)
		(layer "B.Cu")
		(net "FM_S3M_CPU1_LVC1_GPIO_4")
	)
	(arc
		(start 94.550992 -272.314924)
		(mid 94.363794 -272.264781)
		(end 94.176596 -272.314924)
		(width 0.0889)
		(layer "B.Cu")
		(net "FM_S3M_CPU1_LVC1_GPIO_4")
	)
	(arc
		(start 98.860864 -272.32356)
		(mid 98.584423 -272.390726)
		(end 98.310192 -272.314924)
		(width 0.0889)
		(layer "B.Cu")
		(net "FM_S3M_CPU1_LVC1_GPIO_4")
	)
	(arc
		(start 88.912446 -272.314924)
		(mid 88.725248 -272.264781)
		(end 88.53805 -272.314924)
		(width 0.0889)
		(layer "B.Cu")
		(net "FM_S3M_CPU1_LVC1_GPIO_4")
	)
	(arc
		(start 102.069392 -272.314924)
		(mid 101.882194 -272.264781)
		(end 101.694996 -272.314924)
		(width 0.0889)
		(layer "B.Cu")
		(net "FM_S3M_CPU1_LVC1_GPIO_4")
	)
	(arc
		(start 96.985836 -272.32102)
		(mid 96.707404 -272.390834)
		(end 96.430592 -272.314924)
		(width 0.0889)
		(layer "B.Cu")
		(net "FM_S3M_CPU1_LVC1_GPIO_4")
	)
	(arc
		(start 96.041464 -272.32356)
		(mid 95.765023 -272.390726)
		(end 95.490792 -272.314924)
		(width 0.0889)
		(layer "B.Cu")
		(net "FM_S3M_CPU1_LVC1_GPIO_4")
	)
	(arc
		(start 102.620064 -272.32356)
		(mid 102.343623 -272.390726)
		(end 102.069392 -272.314924)
		(width 0.0889)
		(layer "B.Cu")
		(net "FM_S3M_CPU1_LVC1_GPIO_4")
	)
	(arc
		(start 100.740464 -272.32356)
		(mid 100.464023 -272.390726)
		(end 100.189792 -272.314924)
		(width 0.0889)
		(layer "B.Cu")
		(net "FM_S3M_CPU1_LVC1_GPIO_4")
	)
	(arc
		(start 99.800664 -272.32356)
		(mid 99.524223 -272.390726)
		(end 99.249992 -272.314924)
		(width 0.0889)
		(layer "B.Cu")
		(net "FM_S3M_CPU1_LVC1_GPIO_4")
	)
	(arc
		(start 89.467182 -272.32102)
		(mid 89.189004 -272.390712)
		(end 88.912446 -272.314924)
		(width 0.0889)
		(layer "B.Cu")
		(net "FM_S3M_CPU1_LVC1_GPIO_4")
	)
	(arc
		(start 103.192072 -272.581878)
		(mid 102.983789 -272.301532)
		(end 102.634796 -272.314924)
		(width 0.0889)
		(layer "B.Cu")
		(net "FM_S3M_CPU1_LVC1_GPIO_4")
	)
	(arc
		(start 92.282264 -272.32356)
		(mid 92.005823 -272.390726)
		(end 91.731592 -272.314924)
		(width 0.0889)
		(layer "B.Cu")
		(net "FM_S3M_CPU1_LVC1_GPIO_4")
	)
	(segment
		(start 103.291894 -271.289272)
		(end 103.291894 -271.824958)
		(width 0.12954)
		(layer "F.Cu")
		(net "FM_S3M_CPU1_LVC1_GPIO_3")
	)
	(segment
		(start 103.291894 -271.824958)
		(end 103.292148 -271.825212)
		(width 0.12954)
		(layer "F.Cu")
		(net "FM_S3M_CPU1_LVC1_GPIO_3")
	)
	(via
		(at 73.826116 -263.525254)
		(size 0.6604)
		(drill 0.3302)
		(layers "F.Cu" "B.Cu")
		(net "FM_S3M_CPU1_LVC1_GPIO_3")
	)
	(via
		(at 103.292148 -271.825212)
		(size 0.4572)
		(drill 0.2032)
		(layers "F.Cu" "B.Cu")
		(net "FM_S3M_CPU1_LVC1_GPIO_3")
	)
	(segment
		(start 87.17661 -271.260062)
		(end 87.024718 -271.10817)
		(width 0.0889)
		(layer "B.Cu")
		(net "FM_S3M_CPU1_LVC1_GPIO_3")
	)
	(segment
		(start 51.706018 -252.66269)
		(end 51.314858 -253.05385)
		(width 0.12954)
		(layer "B.Cu")
		(net "FM_S3M_CPU1_LVC1_GPIO_3")
	)
	(segment
		(start 51.314858 -253.05385)
		(end 50.733198 -253.05385)
		(width 0.12954)
		(layer "B.Cu")
		(net "FM_S3M_CPU1_LVC1_GPIO_3")
	)
	(segment
		(start 55.414418 -245.75643)
		(end 54.299358 -245.75643)
		(width 0.12954)
		(layer "B.Cu")
		(net "FM_S3M_CPU1_LVC1_GPIO_3")
	)
	(segment
		(start 96.995996 -271.335754)
		(end 96.981264 -271.327118)
		(width 0.0889)
		(layer "B.Cu")
		(net "FM_S3M_CPU1_LVC1_GPIO_3")
	)
	(segment
		(start 89.477596 -271.335754)
		(end 89.462864 -271.327118)
		(width 0.0889)
		(layer "B.Cu")
		(net "FM_S3M_CPU1_LVC1_GPIO_3")
	)
	(segment
		(start 86.75497 -271.10817)
		(end 86.752684 -271.110456)
		(width 0.0889)
		(layer "B.Cu")
		(net "FM_S3M_CPU1_LVC1_GPIO_3")
	)
	(segment
		(start 82.025998 -271.110456)
		(end 82.025744 -271.11071)
		(width 0.12954)
		(layer "B.Cu")
		(net "FM_S3M_CPU1_LVC1_GPIO_3")
	)
	(segment
		(start 53.260498 -246.79529)
		(end 52.998878 -246.79529)
		(width 0.12954)
		(layer "B.Cu")
		(net "FM_S3M_CPU1_LVC1_GPIO_3")
	)
	(segment
		(start 93.236796 -271.335754)
		(end 93.222064 -271.327118)
		(width 0.0889)
		(layer "B.Cu")
		(net "FM_S3M_CPU1_LVC1_GPIO_3")
	)
	(segment
		(start 81.411572 -271.11071)
		(end 73.826116 -263.525254)
		(width 0.12954)
		(layer "B.Cu")
		(net "FM_S3M_CPU1_LVC1_GPIO_3")
	)
	(segment
		(start 51.286918 -197.71233)
		(end 51.714908 -197.28434)
		(width 0.12954)
		(layer "B.Cu")
		(net "FM_S3M_CPU1_LVC1_GPIO_3")
	)
	(segment
		(start 51.714908 -197.28434)
		(end 51.714908 -193.65976)
		(width 0.12954)
		(layer "B.Cu")
		(net "FM_S3M_CPU1_LVC1_GPIO_3")
	)
	(segment
		(start 50.357278 -197.71233)
		(end 51.286918 -197.71233)
		(width 0.12954)
		(layer "B.Cu")
		(net "FM_S3M_CPU1_LVC1_GPIO_3")
	)
	(segment
		(start 99.815396 -271.335754)
		(end 99.800664 -271.327118)
		(width 0.0889)
		(layer "B.Cu")
		(net "FM_S3M_CPU1_LVC1_GPIO_3")
	)
	(segment
		(start 94.17685 -271.335754)
		(end 94.166436 -271.329658)
		(width 0.0889)
		(layer "B.Cu")
		(net "FM_S3M_CPU1_LVC1_GPIO_3")
	)
	(segment
		(start 56.082438 -245.08841)
		(end 55.414418 -245.75643)
		(width 0.12954)
		(layer "B.Cu")
		(net "FM_S3M_CPU1_LVC1_GPIO_3")
	)
	(segment
		(start 82.025744 -271.11071)
		(end 81.411572 -271.11071)
		(width 0.12954)
		(layer "B.Cu")
		(net "FM_S3M_CPU1_LVC1_GPIO_3")
	)
	(segment
		(start 92.296996 -271.335754)
		(end 92.282264 -271.327118)
		(width 0.0889)
		(layer "B.Cu")
		(net "FM_S3M_CPU1_LVC1_GPIO_3")
	)
	(segment
		(start 52.730908 -193.65976)
		(end 51.714908 -193.65976)
		(width 0.12954)
		(layer "B.Cu")
		(net "FM_S3M_CPU1_LVC1_GPIO_3")
	)
	(segment
		(start 54.299358 -245.75643)
		(end 53.260498 -246.79529)
		(width 0.12954)
		(layer "B.Cu")
		(net "FM_S3M_CPU1_LVC1_GPIO_3")
	)
	(segment
		(start 70.597268 -260.296406)
		(end 70.597268 -247.957086)
		(width 0.12954)
		(layer "B.Cu")
		(net "FM_S3M_CPU1_LVC1_GPIO_3")
	)
	(segment
		(start 95.116396 -271.335754)
		(end 95.105982 -271.329658)
		(width 0.0889)
		(layer "B.Cu")
		(net "FM_S3M_CPU1_LVC1_GPIO_3")
	)
	(segment
		(start 96.056196 -271.335754)
		(end 96.041464 -271.327118)
		(width 0.0889)
		(layer "B.Cu")
		(net "FM_S3M_CPU1_LVC1_GPIO_3")
	)
	(segment
		(start 102.634796 -271.335754)
		(end 102.624382 -271.329658)
		(width 0.0889)
		(layer "B.Cu")
		(net "FM_S3M_CPU1_LVC1_GPIO_3")
	)
	(segment
		(start 49.371758 -198.69785)
		(end 50.357278 -197.71233)
		(width 0.12954)
		(layer "B.Cu")
		(net "FM_S3M_CPU1_LVC1_GPIO_3")
	)
	(segment
		(start 51.706018 -248.08815)
		(end 51.706018 -252.66269)
		(width 0.12954)
		(layer "B.Cu")
		(net "FM_S3M_CPU1_LVC1_GPIO_3")
	)
	(segment
		(start 103.292148 -271.825212)
		(end 102.979474 -271.825212)
		(width 0.0889)
		(layer "B.Cu")
		(net "FM_S3M_CPU1_LVC1_GPIO_3")
	)
	(segment
		(start 49.371758 -251.69241)
		(end 49.371758 -198.69785)
		(width 0.12954)
		(layer "B.Cu")
		(net "FM_S3M_CPU1_LVC1_GPIO_3")
	)
	(segment
		(start 69.333872 -246.69369)
		(end 62.818264 -246.69369)
		(width 0.12954)
		(layer "B.Cu")
		(net "FM_S3M_CPU1_LVC1_GPIO_3")
	)
	(segment
		(start 60.197238 -246.14759)
		(end 59.138058 -245.08841)
		(width 0.12954)
		(layer "B.Cu")
		(net "FM_S3M_CPU1_LVC1_GPIO_3")
	)
	(segment
		(start 102.640892 -271.33931)
		(end 102.634796 -271.335754)
		(width 0.0889)
		(layer "B.Cu")
		(net "FM_S3M_CPU1_LVC1_GPIO_3")
	)
	(segment
		(start 87.315294 -271.260062)
		(end 87.17661 -271.260062)
		(width 0.0889)
		(layer "B.Cu")
		(net "FM_S3M_CPU1_LVC1_GPIO_3")
	)
	(segment
		(start 86.752684 -271.110456)
		(end 82.025998 -271.110456)
		(width 0.12954)
		(layer "B.Cu")
		(net "FM_S3M_CPU1_LVC1_GPIO_3")
	)
	(segment
		(start 52.998878 -246.79529)
		(end 51.706018 -248.08815)
		(width 0.12954)
		(layer "B.Cu")
		(net "FM_S3M_CPU1_LVC1_GPIO_3")
	)
	(segment
		(start 102.979474 -271.825212)
		(end 102.913688 -271.759426)
		(width 0.0889)
		(layer "B.Cu")
		(net "FM_S3M_CPU1_LVC1_GPIO_3")
	)
	(segment
		(start 50.733198 -253.05385)
		(end 49.371758 -251.69241)
		(width 0.12954)
		(layer "B.Cu")
		(net "FM_S3M_CPU1_LVC1_GPIO_3")
	)
	(segment
		(start 70.597268 -247.957086)
		(end 69.333872 -246.69369)
		(width 0.12954)
		(layer "B.Cu")
		(net "FM_S3M_CPU1_LVC1_GPIO_3")
	)
	(segment
		(start 100.75545 -271.335754)
		(end 100.745036 -271.329658)
		(width 0.0889)
		(layer "B.Cu")
		(net "FM_S3M_CPU1_LVC1_GPIO_3")
	)
	(segment
		(start 59.138058 -245.08841)
		(end 56.082438 -245.08841)
		(width 0.12954)
		(layer "B.Cu")
		(net "FM_S3M_CPU1_LVC1_GPIO_3")
	)
	(segment
		(start 87.024718 -271.10817)
		(end 86.75497 -271.10817)
		(width 0.0889)
		(layer "B.Cu")
		(net "FM_S3M_CPU1_LVC1_GPIO_3")
	)
	(segment
		(start 62.818264 -246.69369)
		(end 62.272164 -246.14759)
		(width 0.12954)
		(layer "B.Cu")
		(net "FM_S3M_CPU1_LVC1_GPIO_3")
	)
	(segment
		(start 62.272164 -246.14759)
		(end 60.197238 -246.14759)
		(width 0.12954)
		(layer "B.Cu")
		(net "FM_S3M_CPU1_LVC1_GPIO_3")
	)
	(segment
		(start 98.875596 -271.335754)
		(end 98.860864 -271.327118)
		(width 0.0889)
		(layer "B.Cu")
		(net "FM_S3M_CPU1_LVC1_GPIO_3")
	)
	(segment
		(start 73.826116 -263.525254)
		(end 70.597268 -260.296406)
		(width 0.12954)
		(layer "B.Cu")
		(net "FM_S3M_CPU1_LVC1_GPIO_3")
	)
	(arc
		(start 99.249992 -271.335754)
		(mid 99.062794 -271.385897)
		(end 98.875596 -271.335754)
		(width 0.0889)
		(layer "B.Cu")
		(net "FM_S3M_CPU1_LVC1_GPIO_3")
	)
	(arc
		(start 99.800664 -271.327118)
		(mid 99.524189 -271.259798)
		(end 99.249992 -271.335754)
		(width 0.0889)
		(layer "B.Cu")
		(net "FM_S3M_CPU1_LVC1_GPIO_3")
	)
	(arc
		(start 102.624382 -271.329658)
		(mid 102.346204 -271.259935)
		(end 102.069646 -271.335754)
		(width 0.0889)
		(layer "B.Cu")
		(net "FM_S3M_CPU1_LVC1_GPIO_3")
	)
	(arc
		(start 97.935796 -271.335754)
		(mid 97.653094 -271.259978)
		(end 97.370392 -271.335754)
		(width 0.0889)
		(layer "B.Cu")
		(net "FM_S3M_CPU1_LVC1_GPIO_3")
	)
	(arc
		(start 102.069646 -271.335754)
		(mid 101.882448 -271.385897)
		(end 101.69525 -271.335754)
		(width 0.0889)
		(layer "B.Cu")
		(net "FM_S3M_CPU1_LVC1_GPIO_3")
	)
	(arc
		(start 88.912192 -271.335754)
		(mid 88.724994 -271.385897)
		(end 88.537796 -271.335754)
		(width 0.0889)
		(layer "B.Cu")
		(net "FM_S3M_CPU1_LVC1_GPIO_3")
	)
	(arc
		(start 98.860864 -271.327118)
		(mid 98.584389 -271.259798)
		(end 98.310192 -271.335754)
		(width 0.0889)
		(layer "B.Cu")
		(net "FM_S3M_CPU1_LVC1_GPIO_3")
	)
	(arc
		(start 93.222064 -271.327118)
		(mid 92.945589 -271.259798)
		(end 92.671392 -271.335754)
		(width 0.0889)
		(layer "B.Cu")
		(net "FM_S3M_CPU1_LVC1_GPIO_3")
	)
	(arc
		(start 89.462864 -271.327118)
		(mid 89.186389 -271.259798)
		(end 88.912192 -271.335754)
		(width 0.0889)
		(layer "B.Cu")
		(net "FM_S3M_CPU1_LVC1_GPIO_3")
	)
	(arc
		(start 94.166436 -271.329658)
		(mid 93.888004 -271.259812)
		(end 93.611192 -271.335754)
		(width 0.0889)
		(layer "B.Cu")
		(net "FM_S3M_CPU1_LVC1_GPIO_3")
	)
	(arc
		(start 101.69525 -271.335754)
		(mid 101.412548 -271.259978)
		(end 101.129846 -271.335754)
		(width 0.0889)
		(layer "B.Cu")
		(net "FM_S3M_CPU1_LVC1_GPIO_3")
	)
	(arc
		(start 98.310192 -271.335754)
		(mid 98.122994 -271.385897)
		(end 97.935796 -271.335754)
		(width 0.0889)
		(layer "B.Cu")
		(net "FM_S3M_CPU1_LVC1_GPIO_3")
	)
	(arc
		(start 94.551246 -271.335754)
		(mid 94.364048 -271.385897)
		(end 94.17685 -271.335754)
		(width 0.0889)
		(layer "B.Cu")
		(net "FM_S3M_CPU1_LVC1_GPIO_3")
	)
	(arc
		(start 95.490792 -271.335754)
		(mid 95.303594 -271.385897)
		(end 95.116396 -271.335754)
		(width 0.0889)
		(layer "B.Cu")
		(net "FM_S3M_CPU1_LVC1_GPIO_3")
	)
	(arc
		(start 88.537796 -271.335754)
		(mid 88.255094 -271.259978)
		(end 87.972392 -271.335754)
		(width 0.0889)
		(layer "B.Cu")
		(net "FM_S3M_CPU1_LVC1_GPIO_3")
	)
	(arc
		(start 96.981264 -271.327118)
		(mid 96.704789 -271.259798)
		(end 96.430592 -271.335754)
		(width 0.0889)
		(layer "B.Cu")
		(net "FM_S3M_CPU1_LVC1_GPIO_3")
	)
	(arc
		(start 95.105982 -271.329658)
		(mid 94.827804 -271.259935)
		(end 94.551246 -271.335754)
		(width 0.0889)
		(layer "B.Cu")
		(net "FM_S3M_CPU1_LVC1_GPIO_3")
	)
	(arc
		(start 87.972392 -271.335754)
		(mid 87.785194 -271.385897)
		(end 87.597996 -271.335754)
		(width 0.0889)
		(layer "B.Cu")
		(net "FM_S3M_CPU1_LVC1_GPIO_3")
	)
	(arc
		(start 93.611192 -271.335754)
		(mid 93.423994 -271.385897)
		(end 93.236796 -271.335754)
		(width 0.0889)
		(layer "B.Cu")
		(net "FM_S3M_CPU1_LVC1_GPIO_3")
	)
	(arc
		(start 97.370392 -271.335754)
		(mid 97.183194 -271.385897)
		(end 96.995996 -271.335754)
		(width 0.0889)
		(layer "B.Cu")
		(net "FM_S3M_CPU1_LVC1_GPIO_3")
	)
	(arc
		(start 91.357196 -271.335754)
		(mid 91.074494 -271.259978)
		(end 90.791792 -271.335754)
		(width 0.0889)
		(layer "B.Cu")
		(net "FM_S3M_CPU1_LVC1_GPIO_3")
	)
	(arc
		(start 100.189792 -271.335754)
		(mid 100.002594 -271.385897)
		(end 99.815396 -271.335754)
		(width 0.0889)
		(layer "B.Cu")
		(net "FM_S3M_CPU1_LVC1_GPIO_3")
	)
	(arc
		(start 89.851992 -271.335754)
		(mid 89.664794 -271.385897)
		(end 89.477596 -271.335754)
		(width 0.0889)
		(layer "B.Cu")
		(net "FM_S3M_CPU1_LVC1_GPIO_3")
	)
	(arc
		(start 90.417396 -271.335754)
		(mid 90.134694 -271.259978)
		(end 89.851992 -271.335754)
		(width 0.0889)
		(layer "B.Cu")
		(net "FM_S3M_CPU1_LVC1_GPIO_3")
	)
	(arc
		(start 92.671392 -271.335754)
		(mid 92.484194 -271.385897)
		(end 92.296996 -271.335754)
		(width 0.0889)
		(layer "B.Cu")
		(net "FM_S3M_CPU1_LVC1_GPIO_3")
	)
	(arc
		(start 102.913688 -271.759426)
		(mid 102.8264 -271.51747)
		(end 102.640892 -271.33931)
		(width 0.0889)
		(layer "B.Cu")
		(net "FM_S3M_CPU1_LVC1_GPIO_3")
	)
	(arc
		(start 96.430592 -271.335754)
		(mid 96.243394 -271.385897)
		(end 96.056196 -271.335754)
		(width 0.0889)
		(layer "B.Cu")
		(net "FM_S3M_CPU1_LVC1_GPIO_3")
	)
	(arc
		(start 96.041464 -271.327118)
		(mid 95.764989 -271.259798)
		(end 95.490792 -271.335754)
		(width 0.0889)
		(layer "B.Cu")
		(net "FM_S3M_CPU1_LVC1_GPIO_3")
	)
	(arc
		(start 90.791792 -271.335754)
		(mid 90.604594 -271.385897)
		(end 90.417396 -271.335754)
		(width 0.0889)
		(layer "B.Cu")
		(net "FM_S3M_CPU1_LVC1_GPIO_3")
	)
	(arc
		(start 92.282264 -271.327118)
		(mid 92.005789 -271.259798)
		(end 91.731592 -271.335754)
		(width 0.0889)
		(layer "B.Cu")
		(net "FM_S3M_CPU1_LVC1_GPIO_3")
	)
	(arc
		(start 100.745036 -271.329658)
		(mid 100.466604 -271.259812)
		(end 100.189792 -271.335754)
		(width 0.0889)
		(layer "B.Cu")
		(net "FM_S3M_CPU1_LVC1_GPIO_3")
	)
	(arc
		(start 87.597996 -271.335754)
		(mid 87.461627 -271.279312)
		(end 87.315294 -271.260062)
		(width 0.0889)
		(layer "B.Cu")
		(net "FM_S3M_CPU1_LVC1_GPIO_3")
	)
	(arc
		(start 91.731592 -271.335754)
		(mid 91.544394 -271.385897)
		(end 91.357196 -271.335754)
		(width 0.0889)
		(layer "B.Cu")
		(net "FM_S3M_CPU1_LVC1_GPIO_3")
	)
	(arc
		(start 101.129846 -271.335754)
		(mid 100.942648 -271.385897)
		(end 100.75545 -271.335754)
		(width 0.0889)
		(layer "B.Cu")
		(net "FM_S3M_CPU1_LVC1_GPIO_3")
	)
	(segment
		(start 102.352348 -271.289526)
		(end 102.352348 -271.825212)
		(width 0.12954)
		(layer "F.Cu")
		(net "FM_S3M_CPU1_LVC1_GPIO_2")
	)
	(segment
		(start 102.352094 -271.289272)
		(end 102.352348 -271.289526)
		(width 0.12954)
		(layer "F.Cu")
		(net "FM_S3M_CPU1_LVC1_GPIO_2")
	)
	(via
		(at 74.763122 -265.325606)
		(size 0.6604)
		(drill 0.3302)
		(layers "F.Cu" "B.Cu")
		(net "FM_S3M_CPU1_LVC1_GPIO_2")
	)
	(via
		(at 102.352348 -271.825212)
		(size 0.4572)
		(drill 0.2032)
		(layers "F.Cu" "B.Cu")
		(net "FM_S3M_CPU1_LVC1_GPIO_2")
	)
	(segment
		(start 82.025998 -271.481296)
		(end 82.025744 -271.48155)
		(width 0.12954)
		(layer "B.Cu")
		(net "FM_S3M_CPU1_LVC1_GPIO_2")
	)
	(segment
		(start 82.025744 -271.48155)
		(end 80.919066 -271.48155)
		(width 0.12954)
		(layer "B.Cu")
		(net "FM_S3M_CPU1_LVC1_GPIO_2")
	)
	(segment
		(start 70.290182 -248.176288)
		(end 69.120004 -247.00611)
		(width 0.12954)
		(layer "B.Cu")
		(net "FM_S3M_CPU1_LVC1_GPIO_2")
	)
	(segment
		(start 58.784998 -246.35333)
		(end 55.823358 -246.35333)
		(width 0.12954)
		(layer "B.Cu")
		(net "FM_S3M_CPU1_LVC1_GPIO_2")
	)
	(segment
		(start 53.405278 -248.53265)
		(end 53.405278 -251.52477)
		(width 0.12954)
		(layer "B.Cu")
		(net "FM_S3M_CPU1_LVC1_GPIO_2")
	)
	(segment
		(start 102.352348 -271.825212)
		(end 102.665022 -271.825212)
		(width 0.0889)
		(layer "B.Cu")
		(net "FM_S3M_CPU1_LVC1_GPIO_2")
	)
	(segment
		(start 102.548436 -271.505934)
		(end 102.539546 -271.500854)
		(width 0.0889)
		(layer "B.Cu")
		(net "FM_S3M_CPU1_LVC1_GPIO_2")
	)
	(segment
		(start 95.035878 -271.50949)
		(end 95.021146 -271.500854)
		(width 0.0889)
		(layer "B.Cu")
		(net "FM_S3M_CPU1_LVC1_GPIO_2")
	)
	(segment
		(start 69.120004 -247.00611)
		(end 62.922658 -247.00611)
		(width 0.12954)
		(layer "B.Cu")
		(net "FM_S3M_CPU1_LVC1_GPIO_2")
	)
	(segment
		(start 47.862998 -198.09333)
		(end 49.682908 -196.27342)
		(width 0.12954)
		(layer "B.Cu")
		(net "FM_S3M_CPU1_LVC1_GPIO_2")
	)
	(segment
		(start 80.919066 -271.48155)
		(end 74.763122 -265.325606)
		(width 0.12954)
		(layer "B.Cu")
		(net "FM_S3M_CPU1_LVC1_GPIO_2")
	)
	(segment
		(start 50.547778 -253.43485)
		(end 47.862998 -250.75007)
		(width 0.12954)
		(layer "B.Cu")
		(net "FM_S3M_CPU1_LVC1_GPIO_2")
	)
	(segment
		(start 47.862998 -250.75007)
		(end 47.862998 -198.09333)
		(width 0.12954)
		(layer "B.Cu")
		(net "FM_S3M_CPU1_LVC1_GPIO_2")
	)
	(segment
		(start 87.315294 -271.450308)
		(end 87.1474 -271.450308)
		(width 0.0889)
		(layer "B.Cu")
		(net "FM_S3M_CPU1_LVC1_GPIO_2")
	)
	(segment
		(start 88.452706 -271.50695)
		(end 88.442292 -271.500854)
		(width 0.0889)
		(layer "B.Cu")
		(net "FM_S3M_CPU1_LVC1_GPIO_2")
	)
	(segment
		(start 62.922658 -247.00611)
		(end 62.800738 -247.12803)
		(width 0.12954)
		(layer "B.Cu")
		(net "FM_S3M_CPU1_LVC1_GPIO_2")
	)
	(segment
		(start 55.823358 -246.35333)
		(end 55.226458 -246.95023)
		(width 0.12954)
		(layer "B.Cu")
		(net "FM_S3M_CPU1_LVC1_GPIO_2")
	)
	(segment
		(start 102.665022 -271.825212)
		(end 102.722426 -271.767808)
		(width 0.0889)
		(layer "B.Cu")
		(net "FM_S3M_CPU1_LVC1_GPIO_2")
	)
	(segment
		(start 87.1474 -271.450308)
		(end 87.116412 -271.481296)
		(width 0.0889)
		(layer "B.Cu")
		(net "FM_S3M_CPU1_LVC1_GPIO_2")
	)
	(segment
		(start 51.495198 -253.43485)
		(end 50.547778 -253.43485)
		(width 0.12954)
		(layer "B.Cu")
		(net "FM_S3M_CPU1_LVC1_GPIO_2")
	)
	(segment
		(start 91.272106 -271.50695)
		(end 91.261692 -271.500854)
		(width 0.0889)
		(layer "B.Cu")
		(net "FM_S3M_CPU1_LVC1_GPIO_2")
	)
	(segment
		(start 93.156278 -271.50949)
		(end 93.141546 -271.500854)
		(width 0.0889)
		(layer "B.Cu")
		(net "FM_S3M_CPU1_LVC1_GPIO_2")
	)
	(segment
		(start 54.987698 -246.95023)
		(end 53.405278 -248.53265)
		(width 0.12954)
		(layer "B.Cu")
		(net "FM_S3M_CPU1_LVC1_GPIO_2")
	)
	(segment
		(start 74.763122 -265.325606)
		(end 70.290182 -260.852666)
		(width 0.12954)
		(layer "B.Cu")
		(net "FM_S3M_CPU1_LVC1_GPIO_2")
	)
	(segment
		(start 96.91116 -271.50695)
		(end 96.900746 -271.500854)
		(width 0.0889)
		(layer "B.Cu")
		(net "FM_S3M_CPU1_LVC1_GPIO_2")
	)
	(segment
		(start 86.822026 -271.481296)
		(end 82.025998 -271.481296)
		(width 0.12954)
		(layer "B.Cu")
		(net "FM_S3M_CPU1_LVC1_GPIO_2")
	)
	(segment
		(start 62.800738 -247.12803)
		(end 59.559698 -247.12803)
		(width 0.12954)
		(layer "B.Cu")
		(net "FM_S3M_CPU1_LVC1_GPIO_2")
	)
	(segment
		(start 92.216478 -271.50949)
		(end 92.201746 -271.500854)
		(width 0.0889)
		(layer "B.Cu")
		(net "FM_S3M_CPU1_LVC1_GPIO_2")
	)
	(segment
		(start 49.682908 -193.65976)
		(end 50.698908 -193.65976)
		(width 0.12954)
		(layer "B.Cu")
		(net "FM_S3M_CPU1_LVC1_GPIO_2")
	)
	(segment
		(start 98.795078 -271.50949)
		(end 98.780346 -271.500854)
		(width 0.0889)
		(layer "B.Cu")
		(net "FM_S3M_CPU1_LVC1_GPIO_2")
	)
	(segment
		(start 59.559698 -247.12803)
		(end 58.784998 -246.35333)
		(width 0.12954)
		(layer "B.Cu")
		(net "FM_S3M_CPU1_LVC1_GPIO_2")
	)
	(segment
		(start 97.850706 -271.50695)
		(end 97.840292 -271.500854)
		(width 0.0889)
		(layer "B.Cu")
		(net "FM_S3M_CPU1_LVC1_GPIO_2")
	)
	(segment
		(start 89.39276 -271.50695)
		(end 89.382346 -271.500854)
		(width 0.0889)
		(layer "B.Cu")
		(net "FM_S3M_CPU1_LVC1_GPIO_2")
	)
	(segment
		(start 55.226458 -246.95023)
		(end 54.987698 -246.95023)
		(width 0.12954)
		(layer "B.Cu")
		(net "FM_S3M_CPU1_LVC1_GPIO_2")
	)
	(segment
		(start 95.975678 -271.50949)
		(end 95.960946 -271.500854)
		(width 0.0889)
		(layer "B.Cu")
		(net "FM_S3M_CPU1_LVC1_GPIO_2")
	)
	(segment
		(start 49.682908 -196.27342)
		(end 49.682908 -193.65976)
		(width 0.12954)
		(layer "B.Cu")
		(net "FM_S3M_CPU1_LVC1_GPIO_2")
	)
	(segment
		(start 87.116412 -271.481296)
		(end 86.822026 -271.481296)
		(width 0.0889)
		(layer "B.Cu")
		(net "FM_S3M_CPU1_LVC1_GPIO_2")
	)
	(segment
		(start 99.734878 -271.50949)
		(end 99.720146 -271.500854)
		(width 0.0889)
		(layer "B.Cu")
		(net "FM_S3M_CPU1_LVC1_GPIO_2")
	)
	(segment
		(start 70.290182 -260.852666)
		(end 70.290182 -248.176288)
		(width 0.12954)
		(layer "B.Cu")
		(net "FM_S3M_CPU1_LVC1_GPIO_2")
	)
	(segment
		(start 53.405278 -251.52477)
		(end 51.495198 -253.43485)
		(width 0.12954)
		(layer "B.Cu")
		(net "FM_S3M_CPU1_LVC1_GPIO_2")
	)
	(arc
		(start 94.081346 -271.500854)
		(mid 93.894148 -271.450711)
		(end 93.70695 -271.500854)
		(width 0.0889)
		(layer "B.Cu")
		(net "FM_S3M_CPU1_LVC1_GPIO_2")
	)
	(arc
		(start 100.659946 -271.500854)
		(mid 100.472748 -271.450711)
		(end 100.28555 -271.500854)
		(width 0.0889)
		(layer "B.Cu")
		(net "FM_S3M_CPU1_LVC1_GPIO_2")
	)
	(arc
		(start 102.16515 -271.500854)
		(mid 101.882448 -271.57663)
		(end 101.599746 -271.500854)
		(width 0.0889)
		(layer "B.Cu")
		(net "FM_S3M_CPU1_LVC1_GPIO_2")
	)
	(arc
		(start 97.840292 -271.500854)
		(mid 97.653094 -271.450711)
		(end 97.465896 -271.500854)
		(width 0.0889)
		(layer "B.Cu")
		(net "FM_S3M_CPU1_LVC1_GPIO_2")
	)
	(arc
		(start 88.067896 -271.500854)
		(mid 87.785194 -271.57663)
		(end 87.502492 -271.500854)
		(width 0.0889)
		(layer "B.Cu")
		(net "FM_S3M_CPU1_LVC1_GPIO_2")
	)
	(arc
		(start 95.021146 -271.500854)
		(mid 94.833948 -271.450711)
		(end 94.64675 -271.500854)
		(width 0.0889)
		(layer "B.Cu")
		(net "FM_S3M_CPU1_LVC1_GPIO_2")
	)
	(arc
		(start 89.382346 -271.500854)
		(mid 89.195148 -271.450711)
		(end 89.00795 -271.500854)
		(width 0.0889)
		(layer "B.Cu")
		(net "FM_S3M_CPU1_LVC1_GPIO_2")
	)
	(arc
		(start 101.599746 -271.500854)
		(mid 101.412548 -271.450711)
		(end 101.22535 -271.500854)
		(width 0.0889)
		(layer "B.Cu")
		(net "FM_S3M_CPU1_LVC1_GPIO_2")
	)
	(arc
		(start 88.442292 -271.500854)
		(mid 88.255094 -271.450711)
		(end 88.067896 -271.500854)
		(width 0.0889)
		(layer "B.Cu")
		(net "FM_S3M_CPU1_LVC1_GPIO_2")
	)
	(arc
		(start 98.780346 -271.500854)
		(mid 98.593148 -271.450711)
		(end 98.40595 -271.500854)
		(width 0.0889)
		(layer "B.Cu")
		(net "FM_S3M_CPU1_LVC1_GPIO_2")
	)
	(arc
		(start 92.201746 -271.500854)
		(mid 92.014548 -271.450711)
		(end 91.82735 -271.500854)
		(width 0.0889)
		(layer "B.Cu")
		(net "FM_S3M_CPU1_LVC1_GPIO_2")
	)
	(arc
		(start 97.465896 -271.500854)
		(mid 97.189337 -271.576597)
		(end 96.91116 -271.50695)
		(width 0.0889)
		(layer "B.Cu")
		(net "FM_S3M_CPU1_LVC1_GPIO_2")
	)
	(arc
		(start 87.502492 -271.500854)
		(mid 87.41222 -271.463255)
		(end 87.315294 -271.450308)
		(width 0.0889)
		(layer "B.Cu")
		(net "FM_S3M_CPU1_LVC1_GPIO_2")
	)
	(arc
		(start 91.261692 -271.500854)
		(mid 91.074494 -271.450711)
		(end 90.887296 -271.500854)
		(width 0.0889)
		(layer "B.Cu")
		(net "FM_S3M_CPU1_LVC1_GPIO_2")
	)
	(arc
		(start 98.40595 -271.500854)
		(mid 98.129137 -271.576724)
		(end 97.850706 -271.50695)
		(width 0.0889)
		(layer "B.Cu")
		(net "FM_S3M_CPU1_LVC1_GPIO_2")
	)
	(arc
		(start 101.22535 -271.500854)
		(mid 100.942648 -271.57663)
		(end 100.659946 -271.500854)
		(width 0.0889)
		(layer "B.Cu")
		(net "FM_S3M_CPU1_LVC1_GPIO_2")
	)
	(arc
		(start 93.70695 -271.500854)
		(mid 93.432751 -271.576689)
		(end 93.156278 -271.50949)
		(width 0.0889)
		(layer "B.Cu")
		(net "FM_S3M_CPU1_LVC1_GPIO_2")
	)
	(arc
		(start 95.58655 -271.500854)
		(mid 95.312351 -271.576689)
		(end 95.035878 -271.50949)
		(width 0.0889)
		(layer "B.Cu")
		(net "FM_S3M_CPU1_LVC1_GPIO_2")
	)
	(arc
		(start 94.64675 -271.500854)
		(mid 94.364048 -271.57663)
		(end 94.081346 -271.500854)
		(width 0.0889)
		(layer "B.Cu")
		(net "FM_S3M_CPU1_LVC1_GPIO_2")
	)
	(arc
		(start 102.722426 -271.767808)
		(mid 102.66427 -271.617695)
		(end 102.548436 -271.505934)
		(width 0.0889)
		(layer "B.Cu")
		(net "FM_S3M_CPU1_LVC1_GPIO_2")
	)
	(arc
		(start 90.321892 -271.500854)
		(mid 90.134694 -271.450711)
		(end 89.947496 -271.500854)
		(width 0.0889)
		(layer "B.Cu")
		(net "FM_S3M_CPU1_LVC1_GPIO_2")
	)
	(arc
		(start 89.947496 -271.500854)
		(mid 89.670937 -271.576597)
		(end 89.39276 -271.50695)
		(width 0.0889)
		(layer "B.Cu")
		(net "FM_S3M_CPU1_LVC1_GPIO_2")
	)
	(arc
		(start 96.52635 -271.500854)
		(mid 96.252151 -271.576689)
		(end 95.975678 -271.50949)
		(width 0.0889)
		(layer "B.Cu")
		(net "FM_S3M_CPU1_LVC1_GPIO_2")
	)
	(arc
		(start 91.82735 -271.500854)
		(mid 91.550537 -271.576724)
		(end 91.272106 -271.50695)
		(width 0.0889)
		(layer "B.Cu")
		(net "FM_S3M_CPU1_LVC1_GPIO_2")
	)
	(arc
		(start 100.28555 -271.500854)
		(mid 100.011351 -271.576689)
		(end 99.734878 -271.50949)
		(width 0.0889)
		(layer "B.Cu")
		(net "FM_S3M_CPU1_LVC1_GPIO_2")
	)
	(arc
		(start 96.900746 -271.500854)
		(mid 96.713548 -271.450711)
		(end 96.52635 -271.500854)
		(width 0.0889)
		(layer "B.Cu")
		(net "FM_S3M_CPU1_LVC1_GPIO_2")
	)
	(arc
		(start 102.539546 -271.500854)
		(mid 102.352348 -271.450711)
		(end 102.16515 -271.500854)
		(width 0.0889)
		(layer "B.Cu")
		(net "FM_S3M_CPU1_LVC1_GPIO_2")
	)
	(arc
		(start 92.76715 -271.500854)
		(mid 92.492951 -271.576689)
		(end 92.216478 -271.50949)
		(width 0.0889)
		(layer "B.Cu")
		(net "FM_S3M_CPU1_LVC1_GPIO_2")
	)
	(arc
		(start 90.887296 -271.500854)
		(mid 90.604594 -271.57663)
		(end 90.321892 -271.500854)
		(width 0.0889)
		(layer "B.Cu")
		(net "FM_S3M_CPU1_LVC1_GPIO_2")
	)
	(arc
		(start 95.960946 -271.500854)
		(mid 95.773748 -271.450711)
		(end 95.58655 -271.500854)
		(width 0.0889)
		(layer "B.Cu")
		(net "FM_S3M_CPU1_LVC1_GPIO_2")
	)
	(arc
		(start 99.720146 -271.500854)
		(mid 99.532948 -271.450711)
		(end 99.34575 -271.500854)
		(width 0.0889)
		(layer "B.Cu")
		(net "FM_S3M_CPU1_LVC1_GPIO_2")
	)
	(arc
		(start 89.00795 -271.500854)
		(mid 88.731137 -271.576724)
		(end 88.452706 -271.50695)
		(width 0.0889)
		(layer "B.Cu")
		(net "FM_S3M_CPU1_LVC1_GPIO_2")
	)
	(arc
		(start 99.34575 -271.500854)
		(mid 99.071551 -271.576689)
		(end 98.795078 -271.50949)
		(width 0.0889)
		(layer "B.Cu")
		(net "FM_S3M_CPU1_LVC1_GPIO_2")
	)
	(arc
		(start 93.141546 -271.500854)
		(mid 92.954348 -271.450711)
		(end 92.76715 -271.500854)
		(width 0.0889)
		(layer "B.Cu")
		(net "FM_S3M_CPU1_LVC1_GPIO_2")
	)
	(segment
		(start 102.352094 -272.917158)
		(end 102.352094 -273.452844)
		(width 0.12954)
		(layer "F.Cu")
		(net "FM_S3M_CPU1_LVC1_GPIO_1")
	)
	(segment
		(start 102.352094 -273.452844)
		(end 102.352348 -273.453098)
		(width 0.12954)
		(layer "F.Cu")
		(net "FM_S3M_CPU1_LVC1_GPIO_1")
	)
	(via
		(at 102.352348 -273.453098)
		(size 0.4572)
		(drill 0.2032)
		(layers "F.Cu" "B.Cu")
		(net "FM_S3M_CPU1_LVC1_GPIO_1")
	)
	(via
		(at 73.509124 -266.579096)
		(size 0.6604)
		(drill 0.3302)
		(layers "F.Cu" "B.Cu")
		(net "FM_S3M_CPU1_LVC1_GPIO_1")
	)
	(segment
		(start 44.124118 -194.52717)
		(end 44.991528 -193.65976)
		(width 0.12954)
		(layer "B.Cu")
		(net "FM_S3M_CPU1_LVC1_GPIO_1")
	)
	(segment
		(start 94.09176 -273.134836)
		(end 94.081346 -273.12874)
		(width 0.0889)
		(layer "B.Cu")
		(net "FM_S3M_CPU1_LVC1_GPIO_1")
	)
	(segment
		(start 69.067426 -262.137398)
		(end 69.067426 -249.333258)
		(width 0.12954)
		(layer "B.Cu")
		(net "FM_S3M_CPU1_LVC1_GPIO_1")
	)
	(segment
		(start 82.025998 -273.094196)
		(end 82.025744 -273.09445)
		(width 0.12954)
		(layer "B.Cu")
		(net "FM_S3M_CPU1_LVC1_GPIO_1")
	)
	(segment
		(start 90.88755 -273.12874)
		(end 90.877136 -273.134836)
		(width 0.0889)
		(layer "B.Cu")
		(net "FM_S3M_CPU1_LVC1_GPIO_1")
	)
	(segment
		(start 87.361014 -272.963386)
		(end 84.25815 -272.963386)
		(width 0.12954)
		(layer "B.Cu")
		(net "FM_S3M_CPU1_LVC1_GPIO_1")
	)
	(segment
		(start 73.509124 -266.579096)
		(end 69.067426 -262.137398)
		(width 0.12954)
		(layer "B.Cu")
		(net "FM_S3M_CPU1_LVC1_GPIO_1")
	)
	(segment
		(start 87.818468 -272.960592)
		(end 87.815674 -272.963386)
		(width 0.0889)
		(layer "B.Cu")
		(net "FM_S3M_CPU1_LVC1_GPIO_1")
	)
	(segment
		(start 84.25815 -272.963386)
		(end 84.12734 -273.094196)
		(width 0.12954)
		(layer "B.Cu")
		(net "FM_S3M_CPU1_LVC1_GPIO_1")
	)
	(segment
		(start 44.991528 -193.65976)
		(end 46.634908 -193.65976)
		(width 0.12954)
		(layer "B.Cu")
		(net "FM_S3M_CPU1_LVC1_GPIO_1")
	)
	(segment
		(start 51.522884 -255.93167)
		(end 47.329852 -255.93167)
		(width 0.12954)
		(layer "B.Cu")
		(net "FM_S3M_CPU1_LVC1_GPIO_1")
	)
	(segment
		(start 69.067426 -249.333258)
		(end 68.439538 -248.70537)
		(width 0.12954)
		(layer "B.Cu")
		(net "FM_S3M_CPU1_LVC1_GPIO_1")
	)
	(segment
		(start 47.329852 -255.93167)
		(end 45.611288 -254.213106)
		(width 0.12954)
		(layer "B.Cu")
		(net "FM_S3M_CPU1_LVC1_GPIO_1")
	)
	(segment
		(start 92.216478 -273.137376)
		(end 92.201746 -273.12874)
		(width 0.0889)
		(layer "B.Cu")
		(net "FM_S3M_CPU1_LVC1_GPIO_1")
	)
	(segment
		(start 44.124118 -196.21119)
		(end 44.124118 -194.52717)
		(width 0.12954)
		(layer "B.Cu")
		(net "FM_S3M_CPU1_LVC1_GPIO_1")
	)
	(segment
		(start 93.156278 -273.137376)
		(end 93.141546 -273.12874)
		(width 0.0889)
		(layer "B.Cu")
		(net "FM_S3M_CPU1_LVC1_GPIO_1")
	)
	(segment
		(start 59.041538 -248.67489)
		(end 57.890918 -248.67489)
		(width 0.12954)
		(layer "B.Cu")
		(net "FM_S3M_CPU1_LVC1_GPIO_1")
	)
	(segment
		(start 59.232038 -248.86539)
		(end 59.041538 -248.67489)
		(width 0.12954)
		(layer "B.Cu")
		(net "FM_S3M_CPU1_LVC1_GPIO_1")
	)
	(segment
		(start 89.007696 -273.12874)
		(end 88.992964 -273.137376)
		(width 0.0889)
		(layer "B.Cu")
		(net "FM_S3M_CPU1_LVC1_GPIO_1")
	)
	(segment
		(start 62.313312 -248.70537)
		(end 62.153292 -248.86539)
		(width 0.12954)
		(layer "B.Cu")
		(net "FM_S3M_CPU1_LVC1_GPIO_1")
	)
	(segment
		(start 45.035978 -196.45503)
		(end 44.367958 -196.45503)
		(width 0.12954)
		(layer "B.Cu")
		(net "FM_S3M_CPU1_LVC1_GPIO_1")
	)
	(segment
		(start 84.12734 -273.094196)
		(end 82.025998 -273.094196)
		(width 0.12954)
		(layer "B.Cu")
		(net "FM_S3M_CPU1_LVC1_GPIO_1")
	)
	(segment
		(start 87.818722 -272.960592)
		(end 87.818468 -272.960592)
		(width 0.0889)
		(layer "B.Cu")
		(net "FM_S3M_CPU1_LVC1_GPIO_1")
	)
	(segment
		(start 97.855278 -273.137376)
		(end 97.840546 -273.12874)
		(width 0.0889)
		(layer "B.Cu")
		(net "FM_S3M_CPU1_LVC1_GPIO_1")
	)
	(segment
		(start 99.734878 -273.137376)
		(end 99.720146 -273.12874)
		(width 0.0889)
		(layer "B.Cu")
		(net "FM_S3M_CPU1_LVC1_GPIO_1")
	)
	(segment
		(start 55.785258 -251.669296)
		(end 51.522884 -255.93167)
		(width 0.12954)
		(layer "B.Cu")
		(net "FM_S3M_CPU1_LVC1_GPIO_1")
	)
	(segment
		(start 80.024478 -273.09445)
		(end 73.509124 -266.579096)
		(width 0.12954)
		(layer "B.Cu")
		(net "FM_S3M_CPU1_LVC1_GPIO_1")
	)
	(segment
		(start 55.785258 -250.78055)
		(end 55.785258 -251.669296)
		(width 0.12954)
		(layer "B.Cu")
		(net "FM_S3M_CPU1_LVC1_GPIO_1")
	)
	(segment
		(start 101.982016 -273.352768)
		(end 101.599492 -273.12874)
		(width 0.0889)
		(layer "B.Cu")
		(net "FM_S3M_CPU1_LVC1_GPIO_1")
	)
	(segment
		(start 87.815674 -272.963386)
		(end 87.361014 -272.963386)
		(width 0.0889)
		(layer "B.Cu")
		(net "FM_S3M_CPU1_LVC1_GPIO_1")
	)
	(segment
		(start 95.031306 -273.134836)
		(end 95.020892 -273.12874)
		(width 0.0889)
		(layer "B.Cu")
		(net "FM_S3M_CPU1_LVC1_GPIO_1")
	)
	(segment
		(start 45.611288 -197.03034)
		(end 45.035978 -196.45503)
		(width 0.12954)
		(layer "B.Cu")
		(net "FM_S3M_CPU1_LVC1_GPIO_1")
	)
	(segment
		(start 82.025744 -273.09445)
		(end 80.024478 -273.09445)
		(width 0.12954)
		(layer "B.Cu")
		(net "FM_S3M_CPU1_LVC1_GPIO_1")
	)
	(segment
		(start 98.795078 -273.137376)
		(end 98.780346 -273.12874)
		(width 0.0889)
		(layer "B.Cu")
		(net "FM_S3M_CPU1_LVC1_GPIO_1")
	)
	(segment
		(start 68.439538 -248.70537)
		(end 62.313312 -248.70537)
		(width 0.12954)
		(layer "B.Cu")
		(net "FM_S3M_CPU1_LVC1_GPIO_1")
	)
	(segment
		(start 91.276678 -273.137376)
		(end 91.261946 -273.12874)
		(width 0.0889)
		(layer "B.Cu")
		(net "FM_S3M_CPU1_LVC1_GPIO_1")
	)
	(segment
		(start 57.890918 -248.67489)
		(end 55.785258 -250.78055)
		(width 0.12954)
		(layer "B.Cu")
		(net "FM_S3M_CPU1_LVC1_GPIO_1")
	)
	(segment
		(start 44.367958 -196.45503)
		(end 44.124118 -196.21119)
		(width 0.12954)
		(layer "B.Cu")
		(net "FM_S3M_CPU1_LVC1_GPIO_1")
	)
	(segment
		(start 100.67036 -273.134836)
		(end 100.659946 -273.12874)
		(width 0.0889)
		(layer "B.Cu")
		(net "FM_S3M_CPU1_LVC1_GPIO_1")
	)
	(segment
		(start 62.153292 -248.86539)
		(end 59.232038 -248.86539)
		(width 0.12954)
		(layer "B.Cu")
		(net "FM_S3M_CPU1_LVC1_GPIO_1")
	)
	(segment
		(start 95.975678 -273.137376)
		(end 95.960946 -273.12874)
		(width 0.0889)
		(layer "B.Cu")
		(net "FM_S3M_CPU1_LVC1_GPIO_1")
	)
	(segment
		(start 45.611288 -254.213106)
		(end 45.611288 -197.03034)
		(width 0.12954)
		(layer "B.Cu")
		(net "FM_S3M_CPU1_LVC1_GPIO_1")
	)
	(arc
		(start 93.70695 -273.12874)
		(mid 93.432751 -273.204575)
		(end 93.156278 -273.137376)
		(width 0.0889)
		(layer "B.Cu")
		(net "FM_S3M_CPU1_LVC1_GPIO_1")
	)
	(arc
		(start 101.599492 -273.12874)
		(mid 101.412294 -273.078597)
		(end 101.225096 -273.12874)
		(width 0.0889)
		(layer "B.Cu")
		(net "FM_S3M_CPU1_LVC1_GPIO_1")
	)
	(arc
		(start 93.141546 -273.12874)
		(mid 92.954348 -273.078597)
		(end 92.76715 -273.12874)
		(width 0.0889)
		(layer "B.Cu")
		(net "FM_S3M_CPU1_LVC1_GPIO_1")
	)
	(arc
		(start 94.646496 -273.12874)
		(mid 94.369937 -273.204483)
		(end 94.09176 -273.134836)
		(width 0.0889)
		(layer "B.Cu")
		(net "FM_S3M_CPU1_LVC1_GPIO_1")
	)
	(arc
		(start 88.442292 -273.12874)
		(mid 88.14164 -273.003389)
		(end 87.818722 -272.960592)
		(width 0.0889)
		(layer "B.Cu")
		(net "FM_S3M_CPU1_LVC1_GPIO_1")
	)
	(arc
		(start 92.76715 -273.12874)
		(mid 92.492951 -273.204575)
		(end 92.216478 -273.137376)
		(width 0.0889)
		(layer "B.Cu")
		(net "FM_S3M_CPU1_LVC1_GPIO_1")
	)
	(arc
		(start 97.46615 -273.12874)
		(mid 97.183448 -273.204516)
		(end 96.900746 -273.12874)
		(width 0.0889)
		(layer "B.Cu")
		(net "FM_S3M_CPU1_LVC1_GPIO_1")
	)
	(arc
		(start 95.58655 -273.12874)
		(mid 95.309737 -273.20461)
		(end 95.031306 -273.134836)
		(width 0.0889)
		(layer "B.Cu")
		(net "FM_S3M_CPU1_LVC1_GPIO_1")
	)
	(arc
		(start 89.947496 -273.12874)
		(mid 89.664794 -273.204516)
		(end 89.382092 -273.12874)
		(width 0.0889)
		(layer "B.Cu")
		(net "FM_S3M_CPU1_LVC1_GPIO_1")
	)
	(arc
		(start 88.992964 -273.137376)
		(mid 88.716489 -273.204696)
		(end 88.442292 -273.12874)
		(width 0.0889)
		(layer "B.Cu")
		(net "FM_S3M_CPU1_LVC1_GPIO_1")
	)
	(arc
		(start 100.659946 -273.12874)
		(mid 100.472748 -273.078597)
		(end 100.28555 -273.12874)
		(width 0.0889)
		(layer "B.Cu")
		(net "FM_S3M_CPU1_LVC1_GPIO_1")
	)
	(arc
		(start 100.28555 -273.12874)
		(mid 100.011351 -273.204575)
		(end 99.734878 -273.137376)
		(width 0.0889)
		(layer "B.Cu")
		(net "FM_S3M_CPU1_LVC1_GPIO_1")
	)
	(arc
		(start 99.34575 -273.12874)
		(mid 99.071551 -273.204575)
		(end 98.795078 -273.137376)
		(width 0.0889)
		(layer "B.Cu")
		(net "FM_S3M_CPU1_LVC1_GPIO_1")
	)
	(arc
		(start 96.52635 -273.12874)
		(mid 96.252151 -273.204575)
		(end 95.975678 -273.137376)
		(width 0.0889)
		(layer "B.Cu")
		(net "FM_S3M_CPU1_LVC1_GPIO_1")
	)
	(arc
		(start 96.900746 -273.12874)
		(mid 96.713548 -273.078597)
		(end 96.52635 -273.12874)
		(width 0.0889)
		(layer "B.Cu")
		(net "FM_S3M_CPU1_LVC1_GPIO_1")
	)
	(arc
		(start 95.960946 -273.12874)
		(mid 95.773748 -273.078597)
		(end 95.58655 -273.12874)
		(width 0.0889)
		(layer "B.Cu")
		(net "FM_S3M_CPU1_LVC1_GPIO_1")
	)
	(arc
		(start 97.840546 -273.12874)
		(mid 97.653348 -273.078597)
		(end 97.46615 -273.12874)
		(width 0.0889)
		(layer "B.Cu")
		(net "FM_S3M_CPU1_LVC1_GPIO_1")
	)
	(arc
		(start 94.081346 -273.12874)
		(mid 93.894148 -273.078597)
		(end 93.70695 -273.12874)
		(width 0.0889)
		(layer "B.Cu")
		(net "FM_S3M_CPU1_LVC1_GPIO_1")
	)
	(arc
		(start 91.82735 -273.12874)
		(mid 91.553151 -273.204575)
		(end 91.276678 -273.137376)
		(width 0.0889)
		(layer "B.Cu")
		(net "FM_S3M_CPU1_LVC1_GPIO_1")
	)
	(arc
		(start 91.261946 -273.12874)
		(mid 91.074748 -273.078597)
		(end 90.88755 -273.12874)
		(width 0.0889)
		(layer "B.Cu")
		(net "FM_S3M_CPU1_LVC1_GPIO_1")
	)
	(arc
		(start 101.225096 -273.12874)
		(mid 100.948537 -273.204483)
		(end 100.67036 -273.134836)
		(width 0.0889)
		(layer "B.Cu")
		(net "FM_S3M_CPU1_LVC1_GPIO_1")
	)
	(arc
		(start 98.780346 -273.12874)
		(mid 98.593148 -273.078597)
		(end 98.40595 -273.12874)
		(width 0.0889)
		(layer "B.Cu")
		(net "FM_S3M_CPU1_LVC1_GPIO_1")
	)
	(arc
		(start 99.720146 -273.12874)
		(mid 99.532948 -273.078597)
		(end 99.34575 -273.12874)
		(width 0.0889)
		(layer "B.Cu")
		(net "FM_S3M_CPU1_LVC1_GPIO_1")
	)
	(arc
		(start 102.352348 -273.453098)
		(mid 102.160492 -273.427615)
		(end 101.982016 -273.352768)
		(width 0.0889)
		(layer "B.Cu")
		(net "FM_S3M_CPU1_LVC1_GPIO_1")
	)
	(arc
		(start 90.321892 -273.12874)
		(mid 90.134694 -273.078597)
		(end 89.947496 -273.12874)
		(width 0.0889)
		(layer "B.Cu")
		(net "FM_S3M_CPU1_LVC1_GPIO_1")
	)
	(arc
		(start 95.020892 -273.12874)
		(mid 94.833694 -273.078597)
		(end 94.646496 -273.12874)
		(width 0.0889)
		(layer "B.Cu")
		(net "FM_S3M_CPU1_LVC1_GPIO_1")
	)
	(arc
		(start 90.877136 -273.134836)
		(mid 90.598704 -273.204682)
		(end 90.321892 -273.12874)
		(width 0.0889)
		(layer "B.Cu")
		(net "FM_S3M_CPU1_LVC1_GPIO_1")
	)
	(arc
		(start 98.40595 -273.12874)
		(mid 98.131751 -273.204575)
		(end 97.855278 -273.137376)
		(width 0.0889)
		(layer "B.Cu")
		(net "FM_S3M_CPU1_LVC1_GPIO_1")
	)
	(arc
		(start 89.382092 -273.12874)
		(mid 89.194894 -273.078597)
		(end 89.007696 -273.12874)
		(width 0.0889)
		(layer "B.Cu")
		(net "FM_S3M_CPU1_LVC1_GPIO_1")
	)
	(arc
		(start 92.201746 -273.12874)
		(mid 92.014548 -273.078597)
		(end 91.82735 -273.12874)
		(width 0.0889)
		(layer "B.Cu")
		(net "FM_S3M_CPU1_LVC1_GPIO_1")
	)
	(segment
		(start 103.762048 -272.103342)
		(end 103.761794 -272.103596)
		(width 0.12954)
		(layer "F.Cu")
		(net "FM_S3M_CPU1_LVC1_GPIO_0")
	)
	(segment
		(start 103.761794 -272.103596)
		(end 103.761794 -272.639282)
		(width 0.12954)
		(layer "F.Cu")
		(net "FM_S3M_CPU1_LVC1_GPIO_0")
	)
	(via
		(at 103.761794 -272.639282)
		(size 0.4572)
		(drill 0.2032)
		(layers "F.Cu" "B.Cu")
		(net "FM_S3M_CPU1_LVC1_GPIO_0")
	)
	(via
		(at 72.162162 -263.55675)
		(size 0.6604)
		(drill 0.3302)
		(layers "F.Cu" "B.Cu")
		(net "FM_S3M_CPU1_LVC1_GPIO_0")
	)
	(segment
		(start 88.156796 -272.226786)
		(end 87.568786 -272.226786)
		(width 0.0889)
		(layer "B.Cu")
		(net "FM_S3M_CPU1_LVC1_GPIO_0")
	)
	(segment
		(start 100.674678 -272.140934)
		(end 100.659946 -272.14957)
		(width 0.0889)
		(layer "B.Cu")
		(net "FM_S3M_CPU1_LVC1_GPIO_0")
	)
	(segment
		(start 97.850706 -272.143474)
		(end 97.840292 -272.14957)
		(width 0.0889)
		(layer "B.Cu")
		(net "FM_S3M_CPU1_LVC1_GPIO_0")
	)
	(segment
		(start 82.025998 -272.216626)
		(end 82.025744 -272.21688)
		(width 0.12954)
		(layer "B.Cu")
		(net "FM_S3M_CPU1_LVC1_GPIO_0")
	)
	(segment
		(start 59.318398 -247.52427)
		(end 58.790078 -246.99595)
		(width 0.12954)
		(layer "B.Cu")
		(net "FM_S3M_CPU1_LVC1_GPIO_0")
	)
	(segment
		(start 91.272106 -272.143474)
		(end 91.261692 -272.14957)
		(width 0.0889)
		(layer "B.Cu")
		(net "FM_S3M_CPU1_LVC1_GPIO_0")
	)
	(segment
		(start 50.420778 -253.78791)
		(end 47.509938 -250.87707)
		(width 0.12954)
		(layer "B.Cu")
		(net "FM_S3M_CPU1_LVC1_GPIO_0")
	)
	(segment
		(start 58.790078 -246.99595)
		(end 56.199278 -246.99595)
		(width 0.12954)
		(layer "B.Cu")
		(net "FM_S3M_CPU1_LVC1_GPIO_0")
	)
	(segment
		(start 103.44912 -272.639282)
		(end 103.383842 -272.574004)
		(width 0.0889)
		(layer "B.Cu")
		(net "FM_S3M_CPU1_LVC1_GPIO_0")
	)
	(segment
		(start 82.025744 -272.21688)
		(end 80.822292 -272.21688)
		(width 0.12954)
		(layer "B.Cu")
		(net "FM_S3M_CPU1_LVC1_GPIO_0")
	)
	(segment
		(start 87.558626 -272.216626)
		(end 82.025998 -272.216626)
		(width 0.12954)
		(layer "B.Cu")
		(net "FM_S3M_CPU1_LVC1_GPIO_0")
	)
	(segment
		(start 90.887296 -272.14957)
		(end 90.872564 -272.140934)
		(width 0.0889)
		(layer "B.Cu")
		(net "FM_S3M_CPU1_LVC1_GPIO_0")
	)
	(segment
		(start 95.975678 -272.140934)
		(end 95.960946 -272.14957)
		(width 0.0889)
		(layer "B.Cu")
		(net "FM_S3M_CPU1_LVC1_GPIO_0")
	)
	(segment
		(start 103.761794 -272.639282)
		(end 103.44912 -272.639282)
		(width 0.0889)
		(layer "B.Cu")
		(net "FM_S3M_CPU1_LVC1_GPIO_0")
	)
	(segment
		(start 69.439028 -248.08307)
		(end 63.424816 -248.08307)
		(width 0.12954)
		(layer "B.Cu")
		(net "FM_S3M_CPU1_LVC1_GPIO_0")
	)
	(segment
		(start 89.00795 -272.14957)
		(end 88.997536 -272.143474)
		(width 0.0889)
		(layer "B.Cu")
		(net "FM_S3M_CPU1_LVC1_GPIO_0")
	)
	(segment
		(start 101.614478 -272.140934)
		(end 101.599746 -272.14957)
		(width 0.0889)
		(layer "B.Cu")
		(net "FM_S3M_CPU1_LVC1_GPIO_0")
	)
	(segment
		(start 47.509938 -194.81673)
		(end 48.666908 -193.65976)
		(width 0.12954)
		(layer "B.Cu")
		(net "FM_S3M_CPU1_LVC1_GPIO_0")
	)
	(segment
		(start 55.091838 -248.10339)
		(end 55.091838 -250.40209)
		(width 0.12954)
		(layer "B.Cu")
		(net "FM_S3M_CPU1_LVC1_GPIO_0")
	)
	(segment
		(start 87.568786 -272.226786)
		(end 87.558626 -272.216626)
		(width 0.12954)
		(layer "B.Cu")
		(net "FM_S3M_CPU1_LVC1_GPIO_0")
	)
	(segment
		(start 93.156278 -272.140934)
		(end 93.141546 -272.14957)
		(width 0.0889)
		(layer "B.Cu")
		(net "FM_S3M_CPU1_LVC1_GPIO_0")
	)
	(segment
		(start 99.734878 -272.140934)
		(end 99.720146 -272.14957)
		(width 0.0889)
		(layer "B.Cu")
		(net "FM_S3M_CPU1_LVC1_GPIO_0")
	)
	(segment
		(start 94.096078 -272.140934)
		(end 94.081346 -272.14957)
		(width 0.0889)
		(layer "B.Cu")
		(net "FM_S3M_CPU1_LVC1_GPIO_0")
	)
	(segment
		(start 55.091838 -250.40209)
		(end 51.706018 -253.78791)
		(width 0.12954)
		(layer "B.Cu")
		(net "FM_S3M_CPU1_LVC1_GPIO_0")
	)
	(segment
		(start 62.866016 -247.52427)
		(end 59.318398 -247.52427)
		(width 0.12954)
		(layer "B.Cu")
		(net "FM_S3M_CPU1_LVC1_GPIO_0")
	)
	(segment
		(start 72.162162 -263.55675)
		(end 69.925692 -261.32028)
		(width 0.12954)
		(layer "B.Cu")
		(net "FM_S3M_CPU1_LVC1_GPIO_0")
	)
	(segment
		(start 98.795078 -272.140934)
		(end 98.780346 -272.14957)
		(width 0.0889)
		(layer "B.Cu")
		(net "FM_S3M_CPU1_LVC1_GPIO_0")
	)
	(segment
		(start 89.39276 -272.143474)
		(end 89.382346 -272.14957)
		(width 0.0889)
		(layer "B.Cu")
		(net "FM_S3M_CPU1_LVC1_GPIO_0")
	)
	(segment
		(start 56.199278 -246.99595)
		(end 55.091838 -248.10339)
		(width 0.12954)
		(layer "B.Cu")
		(net "FM_S3M_CPU1_LVC1_GPIO_0")
	)
	(segment
		(start 80.822292 -272.21688)
		(end 72.162162 -263.55675)
		(width 0.12954)
		(layer "B.Cu")
		(net "FM_S3M_CPU1_LVC1_GPIO_0")
	)
	(segment
		(start 102.554278 -272.140934)
		(end 102.539546 -272.14957)
		(width 0.0889)
		(layer "B.Cu")
		(net "FM_S3M_CPU1_LVC1_GPIO_0")
	)
	(segment
		(start 92.216478 -272.140934)
		(end 92.201746 -272.14957)
		(width 0.0889)
		(layer "B.Cu")
		(net "FM_S3M_CPU1_LVC1_GPIO_0")
	)
	(segment
		(start 69.925692 -261.32028)
		(end 69.925692 -248.569734)
		(width 0.12954)
		(layer "B.Cu")
		(net "FM_S3M_CPU1_LVC1_GPIO_0")
	)
	(segment
		(start 47.509938 -250.87707)
		(end 47.509938 -194.81673)
		(width 0.12954)
		(layer "B.Cu")
		(net "FM_S3M_CPU1_LVC1_GPIO_0")
	)
	(segment
		(start 95.035878 -272.140934)
		(end 95.021146 -272.14957)
		(width 0.0889)
		(layer "B.Cu")
		(net "FM_S3M_CPU1_LVC1_GPIO_0")
	)
	(segment
		(start 63.424816 -248.08307)
		(end 62.866016 -247.52427)
		(width 0.12954)
		(layer "B.Cu")
		(net "FM_S3M_CPU1_LVC1_GPIO_0")
	)
	(segment
		(start 51.706018 -253.78791)
		(end 50.420778 -253.78791)
		(width 0.12954)
		(layer "B.Cu")
		(net "FM_S3M_CPU1_LVC1_GPIO_0")
	)
	(segment
		(start 97.465896 -272.14957)
		(end 97.455482 -272.143474)
		(width 0.0889)
		(layer "B.Cu")
		(net "FM_S3M_CPU1_LVC1_GPIO_0")
	)
	(segment
		(start 69.925692 -248.569734)
		(end 69.439028 -248.08307)
		(width 0.12954)
		(layer "B.Cu")
		(net "FM_S3M_CPU1_LVC1_GPIO_0")
	)
	(arc
		(start 102.16515 -272.14957)
		(mid 101.890921 -272.073645)
		(end 101.614478 -272.140934)
		(width 0.0889)
		(layer "B.Cu")
		(net "FM_S3M_CPU1_LVC1_GPIO_0")
	)
	(arc
		(start 95.58655 -272.14957)
		(mid 95.312321 -272.073645)
		(end 95.035878 -272.140934)
		(width 0.0889)
		(layer "B.Cu")
		(net "FM_S3M_CPU1_LVC1_GPIO_0")
	)
	(arc
		(start 100.659946 -272.14957)
		(mid 100.472748 -272.199713)
		(end 100.28555 -272.14957)
		(width 0.0889)
		(layer "B.Cu")
		(net "FM_S3M_CPU1_LVC1_GPIO_0")
	)
	(arc
		(start 99.34575 -272.14957)
		(mid 99.071521 -272.073645)
		(end 98.795078 -272.140934)
		(width 0.0889)
		(layer "B.Cu")
		(net "FM_S3M_CPU1_LVC1_GPIO_0")
	)
	(arc
		(start 94.081346 -272.14957)
		(mid 93.894148 -272.199713)
		(end 93.70695 -272.14957)
		(width 0.0889)
		(layer "B.Cu")
		(net "FM_S3M_CPU1_LVC1_GPIO_0")
	)
	(arc
		(start 96.52635 -272.14957)
		(mid 96.252121 -272.073645)
		(end 95.975678 -272.140934)
		(width 0.0889)
		(layer "B.Cu")
		(net "FM_S3M_CPU1_LVC1_GPIO_0")
	)
	(arc
		(start 99.720146 -272.14957)
		(mid 99.532948 -272.199713)
		(end 99.34575 -272.14957)
		(width 0.0889)
		(layer "B.Cu")
		(net "FM_S3M_CPU1_LVC1_GPIO_0")
	)
	(arc
		(start 95.021146 -272.14957)
		(mid 94.833948 -272.199713)
		(end 94.64675 -272.14957)
		(width 0.0889)
		(layer "B.Cu")
		(net "FM_S3M_CPU1_LVC1_GPIO_0")
	)
	(arc
		(start 91.261692 -272.14957)
		(mid 91.074494 -272.199713)
		(end 90.887296 -272.14957)
		(width 0.0889)
		(layer "B.Cu")
		(net "FM_S3M_CPU1_LVC1_GPIO_0")
	)
	(arc
		(start 97.840292 -272.14957)
		(mid 97.653094 -272.199713)
		(end 97.465896 -272.14957)
		(width 0.0889)
		(layer "B.Cu")
		(net "FM_S3M_CPU1_LVC1_GPIO_0")
	)
	(arc
		(start 93.70695 -272.14957)
		(mid 93.432721 -272.073645)
		(end 93.156278 -272.140934)
		(width 0.0889)
		(layer "B.Cu")
		(net "FM_S3M_CPU1_LVC1_GPIO_0")
	)
	(arc
		(start 102.539546 -272.14957)
		(mid 102.352348 -272.199713)
		(end 102.16515 -272.14957)
		(width 0.0889)
		(layer "B.Cu")
		(net "FM_S3M_CPU1_LVC1_GPIO_0")
	)
	(arc
		(start 89.947496 -272.14957)
		(mid 89.670937 -272.073861)
		(end 89.39276 -272.143474)
		(width 0.0889)
		(layer "B.Cu")
		(net "FM_S3M_CPU1_LVC1_GPIO_0")
	)
	(arc
		(start 91.82735 -272.14957)
		(mid 91.550537 -272.073734)
		(end 91.272106 -272.143474)
		(width 0.0889)
		(layer "B.Cu")
		(net "FM_S3M_CPU1_LVC1_GPIO_0")
	)
	(arc
		(start 101.599746 -272.14957)
		(mid 101.412548 -272.199713)
		(end 101.22535 -272.14957)
		(width 0.0889)
		(layer "B.Cu")
		(net "FM_S3M_CPU1_LVC1_GPIO_0")
	)
	(arc
		(start 88.997536 -272.143474)
		(mid 88.719104 -272.07366)
		(end 88.442292 -272.14957)
		(width 0.0889)
		(layer "B.Cu")
		(net "FM_S3M_CPU1_LVC1_GPIO_0")
	)
	(arc
		(start 92.201746 -272.14957)
		(mid 92.014548 -272.199713)
		(end 91.82735 -272.14957)
		(width 0.0889)
		(layer "B.Cu")
		(net "FM_S3M_CPU1_LVC1_GPIO_0")
	)
	(arc
		(start 98.780346 -272.14957)
		(mid 98.593148 -272.199713)
		(end 98.40595 -272.14957)
		(width 0.0889)
		(layer "B.Cu")
		(net "FM_S3M_CPU1_LVC1_GPIO_0")
	)
	(arc
		(start 88.442292 -272.14957)
		(mid 88.304663 -272.207088)
		(end 88.156796 -272.226786)
		(width 0.0889)
		(layer "B.Cu")
		(net "FM_S3M_CPU1_LVC1_GPIO_0")
	)
	(arc
		(start 98.40595 -272.14957)
		(mid 98.129137 -272.073734)
		(end 97.850706 -272.143474)
		(width 0.0889)
		(layer "B.Cu")
		(net "FM_S3M_CPU1_LVC1_GPIO_0")
	)
	(arc
		(start 92.76715 -272.14957)
		(mid 92.492921 -272.073645)
		(end 92.216478 -272.140934)
		(width 0.0889)
		(layer "B.Cu")
		(net "FM_S3M_CPU1_LVC1_GPIO_0")
	)
	(arc
		(start 97.455482 -272.143474)
		(mid 97.177304 -272.073782)
		(end 96.900746 -272.14957)
		(width 0.0889)
		(layer "B.Cu")
		(net "FM_S3M_CPU1_LVC1_GPIO_0")
	)
	(arc
		(start 101.22535 -272.14957)
		(mid 100.951121 -272.073645)
		(end 100.674678 -272.140934)
		(width 0.0889)
		(layer "B.Cu")
		(net "FM_S3M_CPU1_LVC1_GPIO_0")
	)
	(arc
		(start 89.382346 -272.14957)
		(mid 89.195148 -272.199713)
		(end 89.00795 -272.14957)
		(width 0.0889)
		(layer "B.Cu")
		(net "FM_S3M_CPU1_LVC1_GPIO_0")
	)
	(arc
		(start 93.141546 -272.14957)
		(mid 92.954348 -272.199713)
		(end 92.76715 -272.14957)
		(width 0.0889)
		(layer "B.Cu")
		(net "FM_S3M_CPU1_LVC1_GPIO_0")
	)
	(arc
		(start 95.960946 -272.14957)
		(mid 95.773748 -272.199713)
		(end 95.58655 -272.14957)
		(width 0.0889)
		(layer "B.Cu")
		(net "FM_S3M_CPU1_LVC1_GPIO_0")
	)
	(arc
		(start 90.321892 -272.14957)
		(mid 90.134694 -272.199713)
		(end 89.947496 -272.14957)
		(width 0.0889)
		(layer "B.Cu")
		(net "FM_S3M_CPU1_LVC1_GPIO_0")
	)
	(arc
		(start 90.872564 -272.140934)
		(mid 90.596123 -272.073768)
		(end 90.321892 -272.14957)
		(width 0.0889)
		(layer "B.Cu")
		(net "FM_S3M_CPU1_LVC1_GPIO_0")
	)
	(arc
		(start 94.64675 -272.14957)
		(mid 94.372521 -272.073645)
		(end 94.096078 -272.140934)
		(width 0.0889)
		(layer "B.Cu")
		(net "FM_S3M_CPU1_LVC1_GPIO_0")
	)
	(arc
		(start 100.28555 -272.14957)
		(mid 100.011321 -272.073645)
		(end 99.734878 -272.140934)
		(width 0.0889)
		(layer "B.Cu")
		(net "FM_S3M_CPU1_LVC1_GPIO_0")
	)
	(arc
		(start 103.383842 -272.574004)
		(mid 103.083731 -272.137856)
		(end 102.554278 -272.140934)
		(width 0.0889)
		(layer "B.Cu")
		(net "FM_S3M_CPU1_LVC1_GPIO_0")
	)
	(arc
		(start 96.900746 -272.14957)
		(mid 96.713548 -272.199713)
		(end 96.52635 -272.14957)
		(width 0.0889)
		(layer "B.Cu")
		(net "FM_S3M_CPU1_LVC1_GPIO_0")
	)
	(segment
		(start 121.978166 -229.808532)
		(end 121.978166 -229.272846)
		(width 0.12954)
		(layer "F.Cu")
		(net "FM_S3M_CPU1_CPLD_CRC_ERROR")
	)
	(segment
		(start 121.977912 -229.808786)
		(end 121.978166 -229.808532)
		(width 0.12954)
		(layer "F.Cu")
		(net "FM_S3M_CPU1_CPLD_CRC_ERROR")
	)
	(segment
		(start 172.555662 -109.775498)
		(end 172.155612 -109.375448)
		(width 0.12954)
		(layer "F.Cu")
		(net "FM_S3M_CPU1_CPLD_CRC_ERROR")
	)
	(via
		(at 156.782008 -187.795916)
		(size 0.508)
		(drill 0.254)
		(layers "F.Cu" "B.Cu")
		(net "FM_S3M_CPU1_CPLD_CRC_ERROR")
	)
	(via
		(at 121.978166 -229.272846)
		(size 0.4572)
		(drill 0.2032)
		(layers "F.Cu" "B.Cu")
		(net "FM_S3M_CPU1_CPLD_CRC_ERROR")
	)
	(via
		(at 147.59686 -108.45038)
		(size 0.508)
		(drill 0.254)
		(layers "F.Cu" "B.Cu")
		(net "FM_S3M_CPU1_CPLD_CRC_ERROR")
	)
	(via
		(at 172.155612 -109.375448)
		(size 0.4572)
		(drill 0.254)
		(layers "F.Cu" "B.Cu")
		(net "FM_S3M_CPU1_CPLD_CRC_ERROR")
	)
	(via
		(at 146.144996 -225.860864)
		(size 0.6604)
		(drill 0.3302)
		(layers "F.Cu" "B.Cu")
		(net "FM_S3M_CPU1_CPLD_CRC_ERROR")
	)
	(segment
		(start 137.85596 -228.948488)
		(end 138.207242 -228.597206)
		(width 0.12954)
		(layer "B.Cu")
		(net "FM_S3M_CPU1_CPLD_CRC_ERROR")
	)
	(segment
		(start 129.68351 -228.948488)
		(end 129.693924 -228.954584)
		(width 0.0889)
		(layer "B.Cu")
		(net "FM_S3M_CPU1_CPLD_CRC_ERROR")
	)
	(segment
		(start 155.5115 -191.23406)
		(end 156.1465 -190.59906)
		(width 0.12954)
		(layer "B.Cu")
		(net "FM_S3M_CPU1_CPLD_CRC_ERROR")
	)
	(segment
		(start 121.821702 -229.001828)
		(end 121.842784 -228.92385)
		(width 0.0889)
		(layer "B.Cu")
		(net "FM_S3M_CPU1_CPLD_CRC_ERROR")
	)
	(segment
		(start 143.408654 -228.597206)
		(end 146.144996 -225.860864)
		(width 0.12954)
		(layer "B.Cu")
		(net "FM_S3M_CPU1_CPLD_CRC_ERROR")
	)
	(segment
		(start 155.5115 -193.66611)
		(end 155.5115 -191.23406)
		(width 0.12954)
		(layer "B.Cu")
		(net "FM_S3M_CPU1_CPLD_CRC_ERROR")
	)
	(segment
		(start 136.827768 -228.948488)
		(end 137.425176 -228.948488)
		(width 0.0889)
		(layer "B.Cu")
		(net "FM_S3M_CPU1_CPLD_CRC_ERROR")
	)
	(segment
		(start 137.425176 -228.948488)
		(end 137.85596 -228.948488)
		(width 0.12954)
		(layer "B.Cu")
		(net "FM_S3M_CPU1_CPLD_CRC_ERROR")
	)
	(segment
		(start 124.044964 -228.948488)
		(end 124.059696 -228.957124)
		(width 0.0889)
		(layer "B.Cu")
		(net "FM_S3M_CPU1_CPLD_CRC_ERROR")
	)
	(segment
		(start 156.564076 -190.181484)
		(end 156.1465 -190.59906)
		(width 0.12954)
		(layer "B.Cu")
		(net "FM_S3M_CPU1_CPLD_CRC_ERROR")
	)
	(segment
		(start 126.864364 -228.948488)
		(end 126.879096 -228.957124)
		(width 0.0889)
		(layer "B.Cu")
		(net "FM_S3M_CPU1_CPLD_CRC_ERROR")
	)
	(segment
		(start 156.564076 -188.013848)
		(end 156.564076 -190.181484)
		(width 0.12954)
		(layer "B.Cu")
		(net "FM_S3M_CPU1_CPLD_CRC_ERROR")
	)
	(segment
		(start 124.984764 -228.948488)
		(end 124.999496 -228.957124)
		(width 0.0889)
		(layer "B.Cu")
		(net "FM_S3M_CPU1_CPLD_CRC_ERROR")
	)
	(segment
		(start 151.728678 -197.448932)
		(end 155.5115 -193.66611)
		(width 0.12954)
		(layer "B.Cu")
		(net "FM_S3M_CPU1_CPLD_CRC_ERROR")
	)
	(segment
		(start 127.804164 -228.948488)
		(end 127.818896 -228.957124)
		(width 0.0889)
		(layer "B.Cu")
		(net "FM_S3M_CPU1_CPLD_CRC_ERROR")
	)
	(segment
		(start 146.144996 -225.860864)
		(end 151.728678 -220.277182)
		(width 0.12954)
		(layer "B.Cu")
		(net "FM_S3M_CPU1_CPLD_CRC_ERROR")
	)
	(segment
		(start 138.207242 -228.597206)
		(end 143.408654 -228.597206)
		(width 0.12954)
		(layer "B.Cu")
		(net "FM_S3M_CPU1_CPLD_CRC_ERROR")
	)
	(segment
		(start 156.782008 -187.795916)
		(end 156.564076 -188.013848)
		(width 0.12954)
		(layer "B.Cu")
		(net "FM_S3M_CPU1_CPLD_CRC_ERROR")
	)
	(segment
		(start 122.165364 -228.948488)
		(end 122.175778 -228.954584)
		(width 0.0889)
		(layer "B.Cu")
		(net "FM_S3M_CPU1_CPLD_CRC_ERROR")
	)
	(segment
		(start 131.563364 -228.948488)
		(end 131.578096 -228.957124)
		(width 0.0889)
		(layer "B.Cu")
		(net "FM_S3M_CPU1_CPLD_CRC_ERROR")
	)
	(segment
		(start 121.978166 -229.272846)
		(end 121.821702 -229.001828)
		(width 0.0889)
		(layer "B.Cu")
		(net "FM_S3M_CPU1_CPLD_CRC_ERROR")
	)
	(segment
		(start 134.382764 -228.948488)
		(end 134.397496 -228.957124)
		(width 0.0889)
		(layer "B.Cu")
		(net "FM_S3M_CPU1_CPLD_CRC_ERROR")
	)
	(segment
		(start 128.743964 -228.948488)
		(end 128.754378 -228.954584)
		(width 0.0889)
		(layer "B.Cu")
		(net "FM_S3M_CPU1_CPLD_CRC_ERROR")
	)
	(segment
		(start 123.10491 -228.948488)
		(end 123.115324 -228.954584)
		(width 0.0889)
		(layer "B.Cu")
		(net "FM_S3M_CPU1_CPLD_CRC_ERROR")
	)
	(segment
		(start 130.623564 -228.948488)
		(end 130.638296 -228.957124)
		(width 0.0889)
		(layer "B.Cu")
		(net "FM_S3M_CPU1_CPLD_CRC_ERROR")
	)
	(segment
		(start 151.728678 -220.277182)
		(end 151.728678 -197.448932)
		(width 0.12954)
		(layer "B.Cu")
		(net "FM_S3M_CPU1_CPLD_CRC_ERROR")
	)
	(arc
		(start 122.175778 -228.954584)
		(mid 122.453956 -229.024307)
		(end 122.730514 -228.948488)
		(width 0.0889)
		(layer "B.Cu")
		(net "FM_S3M_CPU1_CPLD_CRC_ERROR")
	)
	(arc
		(start 131.188968 -228.948488)
		(mid 131.376166 -228.898345)
		(end 131.563364 -228.948488)
		(width 0.0889)
		(layer "B.Cu")
		(net "FM_S3M_CPU1_CPLD_CRC_ERROR")
	)
	(arc
		(start 124.999496 -228.957124)
		(mid 125.275971 -229.024444)
		(end 125.550168 -228.948488)
		(width 0.0889)
		(layer "B.Cu")
		(net "FM_S3M_CPU1_CPLD_CRC_ERROR")
	)
	(arc
		(start 121.842784 -228.92385)
		(mid 122.00688 -228.899503)
		(end 122.165364 -228.948488)
		(width 0.0889)
		(layer "B.Cu")
		(net "FM_S3M_CPU1_CPLD_CRC_ERROR")
	)
	(arc
		(start 129.309114 -228.948488)
		(mid 129.496312 -228.898345)
		(end 129.68351 -228.948488)
		(width 0.0889)
		(layer "B.Cu")
		(net "FM_S3M_CPU1_CPLD_CRC_ERROR")
	)
	(arc
		(start 132.503164 -228.948488)
		(mid 132.785866 -229.024264)
		(end 133.068568 -228.948488)
		(width 0.0889)
		(layer "B.Cu")
		(net "FM_S3M_CPU1_CPLD_CRC_ERROR")
	)
	(arc
		(start 135.887968 -228.948488)
		(mid 136.075166 -228.898345)
		(end 136.262364 -228.948488)
		(width 0.0889)
		(layer "B.Cu")
		(net "FM_S3M_CPU1_CPLD_CRC_ERROR")
	)
	(arc
		(start 134.948168 -228.948488)
		(mid 135.135366 -228.898345)
		(end 135.322564 -228.948488)
		(width 0.0889)
		(layer "B.Cu")
		(net "FM_S3M_CPU1_CPLD_CRC_ERROR")
	)
	(arc
		(start 128.754378 -228.954584)
		(mid 129.032556 -229.024307)
		(end 129.309114 -228.948488)
		(width 0.0889)
		(layer "B.Cu")
		(net "FM_S3M_CPU1_CPLD_CRC_ERROR")
	)
	(arc
		(start 125.550168 -228.948488)
		(mid 125.737366 -228.898345)
		(end 125.924564 -228.948488)
		(width 0.0889)
		(layer "B.Cu")
		(net "FM_S3M_CPU1_CPLD_CRC_ERROR")
	)
	(arc
		(start 135.322564 -228.948488)
		(mid 135.605266 -229.024264)
		(end 135.887968 -228.948488)
		(width 0.0889)
		(layer "B.Cu")
		(net "FM_S3M_CPU1_CPLD_CRC_ERROR")
	)
	(arc
		(start 133.068568 -228.948488)
		(mid 133.255766 -228.898345)
		(end 133.442964 -228.948488)
		(width 0.0889)
		(layer "B.Cu")
		(net "FM_S3M_CPU1_CPLD_CRC_ERROR")
	)
	(arc
		(start 123.115324 -228.954584)
		(mid 123.393756 -229.02443)
		(end 123.670568 -228.948488)
		(width 0.0889)
		(layer "B.Cu")
		(net "FM_S3M_CPU1_CPLD_CRC_ERROR")
	)
	(arc
		(start 132.128768 -228.948488)
		(mid 132.315966 -228.898345)
		(end 132.503164 -228.948488)
		(width 0.0889)
		(layer "B.Cu")
		(net "FM_S3M_CPU1_CPLD_CRC_ERROR")
	)
	(arc
		(start 126.489968 -228.948488)
		(mid 126.677166 -228.898345)
		(end 126.864364 -228.948488)
		(width 0.0889)
		(layer "B.Cu")
		(net "FM_S3M_CPU1_CPLD_CRC_ERROR")
	)
	(arc
		(start 126.879096 -228.957124)
		(mid 127.155571 -229.024444)
		(end 127.429768 -228.948488)
		(width 0.0889)
		(layer "B.Cu")
		(net "FM_S3M_CPU1_CPLD_CRC_ERROR")
	)
	(arc
		(start 125.924564 -228.948488)
		(mid 126.207266 -229.024264)
		(end 126.489968 -228.948488)
		(width 0.0889)
		(layer "B.Cu")
		(net "FM_S3M_CPU1_CPLD_CRC_ERROR")
	)
	(arc
		(start 124.059696 -228.957124)
		(mid 124.336171 -229.024444)
		(end 124.610368 -228.948488)
		(width 0.0889)
		(layer "B.Cu")
		(net "FM_S3M_CPU1_CPLD_CRC_ERROR")
	)
	(arc
		(start 127.818896 -228.957124)
		(mid 128.095371 -229.024444)
		(end 128.369568 -228.948488)
		(width 0.0889)
		(layer "B.Cu")
		(net "FM_S3M_CPU1_CPLD_CRC_ERROR")
	)
	(arc
		(start 134.397496 -228.957124)
		(mid 134.673971 -229.024444)
		(end 134.948168 -228.948488)
		(width 0.0889)
		(layer "B.Cu")
		(net "FM_S3M_CPU1_CPLD_CRC_ERROR")
	)
	(arc
		(start 134.008368 -228.948488)
		(mid 134.195566 -228.898345)
		(end 134.382764 -228.948488)
		(width 0.0889)
		(layer "B.Cu")
		(net "FM_S3M_CPU1_CPLD_CRC_ERROR")
	)
	(arc
		(start 128.369568 -228.948488)
		(mid 128.556766 -228.898345)
		(end 128.743964 -228.948488)
		(width 0.0889)
		(layer "B.Cu")
		(net "FM_S3M_CPU1_CPLD_CRC_ERROR")
	)
	(arc
		(start 122.730514 -228.948488)
		(mid 122.917712 -228.898345)
		(end 123.10491 -228.948488)
		(width 0.0889)
		(layer "B.Cu")
		(net "FM_S3M_CPU1_CPLD_CRC_ERROR")
	)
	(arc
		(start 129.693924 -228.954584)
		(mid 129.972356 -229.02443)
		(end 130.249168 -228.948488)
		(width 0.0889)
		(layer "B.Cu")
		(net "FM_S3M_CPU1_CPLD_CRC_ERROR")
	)
	(arc
		(start 130.249168 -228.948488)
		(mid 130.436366 -228.898345)
		(end 130.623564 -228.948488)
		(width 0.0889)
		(layer "B.Cu")
		(net "FM_S3M_CPU1_CPLD_CRC_ERROR")
	)
	(arc
		(start 123.670568 -228.948488)
		(mid 123.857766 -228.898345)
		(end 124.044964 -228.948488)
		(width 0.0889)
		(layer "B.Cu")
		(net "FM_S3M_CPU1_CPLD_CRC_ERROR")
	)
	(arc
		(start 136.262364 -228.948488)
		(mid 136.545066 -229.024264)
		(end 136.827768 -228.948488)
		(width 0.0889)
		(layer "B.Cu")
		(net "FM_S3M_CPU1_CPLD_CRC_ERROR")
	)
	(arc
		(start 133.442964 -228.948488)
		(mid 133.725666 -229.024264)
		(end 134.008368 -228.948488)
		(width 0.0889)
		(layer "B.Cu")
		(net "FM_S3M_CPU1_CPLD_CRC_ERROR")
	)
	(arc
		(start 131.578096 -228.957124)
		(mid 131.854571 -229.024444)
		(end 132.128768 -228.948488)
		(width 0.0889)
		(layer "B.Cu")
		(net "FM_S3M_CPU1_CPLD_CRC_ERROR")
	)
	(arc
		(start 124.610368 -228.948488)
		(mid 124.797566 -228.898345)
		(end 124.984764 -228.948488)
		(width 0.0889)
		(layer "B.Cu")
		(net "FM_S3M_CPU1_CPLD_CRC_ERROR")
	)
	(arc
		(start 127.429768 -228.948488)
		(mid 127.616966 -228.898345)
		(end 127.804164 -228.948488)
		(width 0.0889)
		(layer "B.Cu")
		(net "FM_S3M_CPU1_CPLD_CRC_ERROR")
	)
	(arc
		(start 130.638296 -228.957124)
		(mid 130.914771 -229.024444)
		(end 131.188968 -228.948488)
		(width 0.0889)
		(layer "B.Cu")
		(net "FM_S3M_CPU1_CPLD_CRC_ERROR")
	)
	(segment
		(start 144.48028 -136.362948)
		(end 144.48028 -145.430748)
		(width 0.127)
		(layer "In2.Cu")
		(net "FM_S3M_CPU1_CPLD_CRC_ERROR")
	)
	(segment
		(start 144.563338 -148.554948)
		(end 144.563338 -173.047406)
		(width 0.127)
		(layer "In2.Cu")
		(net "FM_S3M_CPU1_CPLD_CRC_ERROR")
	)
	(segment
		(start 143.588232 -135.4709)
		(end 144.48028 -136.362948)
		(width 0.127)
		(layer "In2.Cu")
		(net "FM_S3M_CPU1_CPLD_CRC_ERROR")
	)
	(segment
		(start 146.829272 -110.023148)
		(end 146.76628 -110.023148)
		(width 0.127)
		(layer "In2.Cu")
		(net "FM_S3M_CPU1_CPLD_CRC_ERROR")
	)
	(segment
		(start 147.59686 -109.25556)
		(end 146.829272 -110.023148)
		(width 0.127)
		(layer "In2.Cu")
		(net "FM_S3M_CPU1_CPLD_CRC_ERROR")
	)
	(segment
		(start 143.64208 -146.268948)
		(end 143.64208 -147.63369)
		(width 0.127)
		(layer "In2.Cu")
		(net "FM_S3M_CPU1_CPLD_CRC_ERROR")
	)
	(segment
		(start 147.59686 -108.45038)
		(end 147.59686 -109.25556)
		(width 0.127)
		(layer "In2.Cu")
		(net "FM_S3M_CPU1_CPLD_CRC_ERROR")
	)
	(segment
		(start 144.563338 -173.047406)
		(end 156.782008 -185.266076)
		(width 0.127)
		(layer "In2.Cu")
		(net "FM_S3M_CPU1_CPLD_CRC_ERROR")
	)
	(segment
		(start 156.782008 -185.266076)
		(end 156.782008 -187.795916)
		(width 0.127)
		(layer "In2.Cu")
		(net "FM_S3M_CPU1_CPLD_CRC_ERROR")
	)
	(segment
		(start 144.48028 -145.430748)
		(end 143.64208 -146.268948)
		(width 0.127)
		(layer "In2.Cu")
		(net "FM_S3M_CPU1_CPLD_CRC_ERROR")
	)
	(segment
		(start 143.64208 -147.63369)
		(end 144.563338 -148.554948)
		(width 0.127)
		(layer "In2.Cu")
		(net "FM_S3M_CPU1_CPLD_CRC_ERROR")
	)
	(segment
		(start 143.588232 -113.201196)
		(end 143.588232 -135.4709)
		(width 0.127)
		(layer "In2.Cu")
		(net "FM_S3M_CPU1_CPLD_CRC_ERROR")
	)
	(segment
		(start 146.76628 -110.023148)
		(end 143.588232 -113.201196)
		(width 0.127)
		(layer "In2.Cu")
		(net "FM_S3M_CPU1_CPLD_CRC_ERROR")
	)
	(segment
		(start 170.23588 -109.896148)
		(end 171.45508 -109.896148)
		(width 0.127)
		(layer "In15.Cu")
		(net "FM_S3M_CPU1_CPLD_CRC_ERROR")
	)
	(segment
		(start 152.10028 -110.200948)
		(end 163.78428 -110.200948)
		(width 0.127)
		(layer "In15.Cu")
		(net "FM_S3M_CPU1_CPLD_CRC_ERROR")
	)
	(segment
		(start 164.39388 -109.591348)
		(end 169.93108 -109.591348)
		(width 0.127)
		(layer "In15.Cu")
		(net "FM_S3M_CPU1_CPLD_CRC_ERROR")
	)
	(segment
		(start 171.45508 -109.896148)
		(end 171.97578 -109.375448)
		(width 0.127)
		(layer "In15.Cu")
		(net "FM_S3M_CPU1_CPLD_CRC_ERROR")
	)
	(segment
		(start 169.93108 -109.591348)
		(end 170.23588 -109.896148)
		(width 0.127)
		(layer "In15.Cu")
		(net "FM_S3M_CPU1_CPLD_CRC_ERROR")
	)
	(segment
		(start 147.59686 -108.45038)
		(end 148.096224 -108.949998)
		(width 0.127)
		(layer "In15.Cu")
		(net "FM_S3M_CPU1_CPLD_CRC_ERROR")
	)
	(segment
		(start 163.78428 -110.200948)
		(end 164.39388 -109.591348)
		(width 0.127)
		(layer "In15.Cu")
		(net "FM_S3M_CPU1_CPLD_CRC_ERROR")
	)
	(segment
		(start 171.97578 -109.375448)
		(end 172.155612 -109.375448)
		(width 0.127)
		(layer "In15.Cu")
		(net "FM_S3M_CPU1_CPLD_CRC_ERROR")
	)
	(segment
		(start 148.096224 -108.949998)
		(end 150.84933 -108.949998)
		(width 0.127)
		(layer "In15.Cu")
		(net "FM_S3M_CPU1_CPLD_CRC_ERROR")
	)
	(segment
		(start 150.84933 -108.949998)
		(end 152.10028 -110.200948)
		(width 0.127)
		(layer "In15.Cu")
		(net "FM_S3M_CPU1_CPLD_CRC_ERROR")
	)
	(segment
		(start 117.388894 -268.033754)
		(end 117.388894 -268.569694)
		(width 0.12954)
		(layer "F.Cu")
		(net "FM_S3M_CPU1_CPLD_CONFIG_N")
	)
	(via
		(at 117.388894 -268.569694)
		(size 0.4572)
		(drill 0.2032)
		(layers "F.Cu" "B.Cu")
		(net "FM_S3M_CPU1_CPLD_CONFIG_N")
	)
	(via
		(at 152.380696 -268.983206)
		(size 0.6604)
		(drill 0.3302)
		(layers "F.Cu" "B.Cu")
		(net "FM_S3M_CPU1_CPLD_CONFIG_N")
	)
	(segment
		(start 180.926486 -253.048516)
		(end 180.926486 -255.236472)
		(width 0.12954)
		(layer "B.Cu")
		(net "FM_S3M_CPU1_CPLD_CONFIG_N")
	)
	(segment
		(start 126.049278 -268.885416)
		(end 126.034546 -268.894052)
		(width 0.0889)
		(layer "B.Cu")
		(net "FM_S3M_CPU1_CPLD_CONFIG_N")
	)
	(segment
		(start 171.116244 -258.393184)
		(end 171.116244 -268.50975)
		(width 0.12954)
		(layer "B.Cu")
		(net "FM_S3M_CPU1_CPLD_CONFIG_N")
	)
	(segment
		(start 124.169678 -268.885416)
		(end 124.154946 -268.894052)
		(width 0.0889)
		(layer "B.Cu")
		(net "FM_S3M_CPU1_CPLD_CONFIG_N")
	)
	(segment
		(start 120.405906 -268.887956)
		(end 120.395492 -268.894052)
		(width 0.0889)
		(layer "B.Cu")
		(net "FM_S3M_CPU1_CPLD_CONFIG_N")
	)
	(segment
		(start 179.022248 -257.14071)
		(end 173.07052 -257.14071)
		(width 0.12954)
		(layer "B.Cu")
		(net "FM_S3M_CPU1_CPLD_CONFIG_N")
	)
	(segment
		(start 125.109478 -268.885416)
		(end 125.094746 -268.894052)
		(width 0.0889)
		(layer "B.Cu")
		(net "FM_S3M_CPU1_CPLD_CONFIG_N")
	)
	(segment
		(start 155.367228 -268.983206)
		(end 152.380696 -268.983206)
		(width 0.12954)
		(layer "B.Cu")
		(net "FM_S3M_CPU1_CPLD_CONFIG_N")
	)
	(segment
		(start 165.348158 -271.06245)
		(end 164.59327 -271.817338)
		(width 0.12954)
		(layer "B.Cu")
		(net "FM_S3M_CPU1_CPLD_CONFIG_N")
	)
	(segment
		(start 131.688078 -268.885416)
		(end 131.673346 -268.894052)
		(width 0.0889)
		(layer "B.Cu")
		(net "FM_S3M_CPU1_CPLD_CONFIG_N")
	)
	(segment
		(start 134.507478 -268.885416)
		(end 134.492746 -268.894052)
		(width 0.0889)
		(layer "B.Cu")
		(net "FM_S3M_CPU1_CPLD_CONFIG_N")
	)
	(segment
		(start 128.868678 -268.885416)
		(end 128.853946 -268.894052)
		(width 0.0889)
		(layer "B.Cu")
		(net "FM_S3M_CPU1_CPLD_CONFIG_N")
	)
	(segment
		(start 171.116244 -268.50975)
		(end 168.563544 -271.06245)
		(width 0.12954)
		(layer "B.Cu")
		(net "FM_S3M_CPU1_CPLD_CONFIG_N")
	)
	(segment
		(start 123.225306 -268.887956)
		(end 123.214892 -268.894052)
		(width 0.0889)
		(layer "B.Cu")
		(net "FM_S3M_CPU1_CPLD_CONFIG_N")
	)
	(segment
		(start 171.300648 -258.08559)
		(end 171.116244 -258.393184)
		(width 0.12954)
		(layer "B.Cu")
		(net "FM_S3M_CPU1_CPLD_CONFIG_N")
	)
	(segment
		(start 160.05683 -270.88211)
		(end 157.266132 -270.88211)
		(width 0.12954)
		(layer "B.Cu")
		(net "FM_S3M_CPU1_CPLD_CONFIG_N")
	)
	(segment
		(start 152.380696 -268.983206)
		(end 138.452352 -268.983206)
		(width 0.12954)
		(layer "B.Cu")
		(net "FM_S3M_CPU1_CPLD_CONFIG_N")
	)
	(segment
		(start 180.926486 -255.236472)
		(end 179.022248 -257.14071)
		(width 0.12954)
		(layer "B.Cu")
		(net "FM_S3M_CPU1_CPLD_CONFIG_N")
	)
	(segment
		(start 138.452352 -268.983206)
		(end 137.268204 -268.983206)
		(width 0.0889)
		(layer "B.Cu")
		(net "FM_S3M_CPU1_CPLD_CONFIG_N")
	)
	(segment
		(start 130.748278 -268.885416)
		(end 130.733546 -268.894052)
		(width 0.0889)
		(layer "B.Cu")
		(net "FM_S3M_CPU1_CPLD_CONFIG_N")
	)
	(segment
		(start 119.081296 -268.894052)
		(end 119.070882 -268.887956)
		(width 0.0889)
		(layer "B.Cu")
		(net "FM_S3M_CPU1_CPLD_CONFIG_N")
	)
	(segment
		(start 129.808478 -268.885416)
		(end 129.793746 -268.894052)
		(width 0.0889)
		(layer "B.Cu")
		(net "FM_S3M_CPU1_CPLD_CONFIG_N")
	)
	(segment
		(start 126.989078 -268.885416)
		(end 126.974346 -268.894052)
		(width 0.0889)
		(layer "B.Cu")
		(net "FM_S3M_CPU1_CPLD_CONFIG_N")
	)
	(segment
		(start 118.14175 -268.894052)
		(end 118.131336 -268.887956)
		(width 0.0889)
		(layer "B.Cu")
		(net "FM_S3M_CPU1_CPLD_CONFIG_N")
	)
	(segment
		(start 157.266132 -270.88211)
		(end 155.367228 -268.983206)
		(width 0.12954)
		(layer "B.Cu")
		(net "FM_S3M_CPU1_CPLD_CONFIG_N")
	)
	(segment
		(start 164.59327 -271.817338)
		(end 160.992058 -271.817338)
		(width 0.12954)
		(layer "B.Cu")
		(net "FM_S3M_CPU1_CPLD_CONFIG_N")
	)
	(segment
		(start 117.634512 -268.864588)
		(end 117.545358 -268.840712)
		(width 0.0889)
		(layer "B.Cu")
		(net "FM_S3M_CPU1_CPLD_CONFIG_N")
	)
	(segment
		(start 135.44296 -268.887956)
		(end 135.432546 -268.894052)
		(width 0.0889)
		(layer "B.Cu")
		(net "FM_S3M_CPU1_CPLD_CONFIG_N")
	)
	(segment
		(start 117.545358 -268.840712)
		(end 117.388894 -268.569694)
		(width 0.0889)
		(layer "B.Cu")
		(net "FM_S3M_CPU1_CPLD_CONFIG_N")
	)
	(segment
		(start 120.021096 -268.894052)
		(end 120.006364 -268.885416)
		(width 0.0889)
		(layer "B.Cu")
		(net "FM_S3M_CPU1_CPLD_CONFIG_N")
	)
	(segment
		(start 160.992058 -271.817338)
		(end 160.05683 -270.88211)
		(width 0.12954)
		(layer "B.Cu")
		(net "FM_S3M_CPU1_CPLD_CONFIG_N")
	)
	(segment
		(start 182.546752 -193.099944)
		(end 182.546752 -194.03314)
		(width 0.12954)
		(layer "B.Cu")
		(net "FM_S3M_CPU1_CPLD_CONFIG_N")
	)
	(segment
		(start 182.546752 -194.03314)
		(end 182.076598 -194.503294)
		(width 0.12954)
		(layer "B.Cu")
		(net "FM_S3M_CPU1_CPLD_CONFIG_N")
	)
	(segment
		(start 173.07052 -257.14071)
		(end 171.300648 -258.08559)
		(width 0.12954)
		(layer "B.Cu")
		(net "FM_S3M_CPU1_CPLD_CONFIG_N")
	)
	(segment
		(start 133.567678 -268.885416)
		(end 133.552946 -268.894052)
		(width 0.0889)
		(layer "B.Cu")
		(net "FM_S3M_CPU1_CPLD_CONFIG_N")
	)
	(segment
		(start 182.076598 -251.898404)
		(end 180.926486 -253.048516)
		(width 0.12954)
		(layer "B.Cu")
		(net "FM_S3M_CPU1_CPLD_CONFIG_N")
	)
	(segment
		(start 168.563544 -271.06245)
		(end 165.348158 -271.06245)
		(width 0.12954)
		(layer "B.Cu")
		(net "FM_S3M_CPU1_CPLD_CONFIG_N")
	)
	(segment
		(start 182.076598 -194.503294)
		(end 182.076598 -251.898404)
		(width 0.12954)
		(layer "B.Cu")
		(net "FM_S3M_CPU1_CPLD_CONFIG_N")
	)
	(segment
		(start 121.900696 -268.894052)
		(end 121.890282 -268.887956)
		(width 0.0889)
		(layer "B.Cu")
		(net "FM_S3M_CPU1_CPLD_CONFIG_N")
	)
	(segment
		(start 127.928878 -268.885416)
		(end 127.914146 -268.894052)
		(width 0.0889)
		(layer "B.Cu")
		(net "FM_S3M_CPU1_CPLD_CONFIG_N")
	)
	(arc
		(start 118.131336 -268.887956)
		(mid 117.88563 -268.818702)
		(end 117.634512 -268.864588)
		(width 0.0889)
		(layer "B.Cu")
		(net "FM_S3M_CPU1_CPLD_CONFIG_N")
	)
	(arc
		(start 131.29895 -268.894052)
		(mid 131.024751 -268.818217)
		(end 130.748278 -268.885416)
		(width 0.0889)
		(layer "B.Cu")
		(net "FM_S3M_CPU1_CPLD_CONFIG_N")
	)
	(arc
		(start 136.937496 -268.894052)
		(mid 136.654794 -268.818276)
		(end 136.372092 -268.894052)
		(width 0.0889)
		(layer "B.Cu")
		(net "FM_S3M_CPU1_CPLD_CONFIG_N")
	)
	(arc
		(start 124.154946 -268.894052)
		(mid 123.967748 -268.944195)
		(end 123.78055 -268.894052)
		(width 0.0889)
		(layer "B.Cu")
		(net "FM_S3M_CPU1_CPLD_CONFIG_N")
	)
	(arc
		(start 129.793746 -268.894052)
		(mid 129.606548 -268.944195)
		(end 129.41935 -268.894052)
		(width 0.0889)
		(layer "B.Cu")
		(net "FM_S3M_CPU1_CPLD_CONFIG_N")
	)
	(arc
		(start 130.35915 -268.894052)
		(mid 130.084951 -268.818217)
		(end 129.808478 -268.885416)
		(width 0.0889)
		(layer "B.Cu")
		(net "FM_S3M_CPU1_CPLD_CONFIG_N")
	)
	(arc
		(start 137.268204 -268.983206)
		(mid 137.096948 -268.960524)
		(end 136.937496 -268.894052)
		(width 0.0889)
		(layer "B.Cu")
		(net "FM_S3M_CPU1_CPLD_CONFIG_N")
	)
	(arc
		(start 121.890282 -268.887956)
		(mid 121.612104 -268.818233)
		(end 121.335546 -268.894052)
		(width 0.0889)
		(layer "B.Cu")
		(net "FM_S3M_CPU1_CPLD_CONFIG_N")
	)
	(arc
		(start 130.733546 -268.894052)
		(mid 130.546348 -268.944195)
		(end 130.35915 -268.894052)
		(width 0.0889)
		(layer "B.Cu")
		(net "FM_S3M_CPU1_CPLD_CONFIG_N")
	)
	(arc
		(start 136.372092 -268.894052)
		(mid 136.184894 -268.944195)
		(end 135.997696 -268.894052)
		(width 0.0889)
		(layer "B.Cu")
		(net "FM_S3M_CPU1_CPLD_CONFIG_N")
	)
	(arc
		(start 132.613146 -268.894052)
		(mid 132.425948 -268.944195)
		(end 132.23875 -268.894052)
		(width 0.0889)
		(layer "B.Cu")
		(net "FM_S3M_CPU1_CPLD_CONFIG_N")
	)
	(arc
		(start 126.59995 -268.894052)
		(mid 126.325751 -268.818217)
		(end 126.049278 -268.885416)
		(width 0.0889)
		(layer "B.Cu")
		(net "FM_S3M_CPU1_CPLD_CONFIG_N")
	)
	(arc
		(start 125.094746 -268.894052)
		(mid 124.907548 -268.944195)
		(end 124.72035 -268.894052)
		(width 0.0889)
		(layer "B.Cu")
		(net "FM_S3M_CPU1_CPLD_CONFIG_N")
	)
	(arc
		(start 126.974346 -268.894052)
		(mid 126.787148 -268.944195)
		(end 126.59995 -268.894052)
		(width 0.0889)
		(layer "B.Cu")
		(net "FM_S3M_CPU1_CPLD_CONFIG_N")
	)
	(arc
		(start 133.552946 -268.894052)
		(mid 133.365748 -268.944195)
		(end 133.17855 -268.894052)
		(width 0.0889)
		(layer "B.Cu")
		(net "FM_S3M_CPU1_CPLD_CONFIG_N")
	)
	(arc
		(start 120.96115 -268.894052)
		(mid 120.684337 -268.818182)
		(end 120.405906 -268.887956)
		(width 0.0889)
		(layer "B.Cu")
		(net "FM_S3M_CPU1_CPLD_CONFIG_N")
	)
	(arc
		(start 125.66015 -268.894052)
		(mid 125.385951 -268.818217)
		(end 125.109478 -268.885416)
		(width 0.0889)
		(layer "B.Cu")
		(net "FM_S3M_CPU1_CPLD_CONFIG_N")
	)
	(arc
		(start 119.070882 -268.887956)
		(mid 118.792704 -268.818233)
		(end 118.516146 -268.894052)
		(width 0.0889)
		(layer "B.Cu")
		(net "FM_S3M_CPU1_CPLD_CONFIG_N")
	)
	(arc
		(start 134.11835 -268.894052)
		(mid 133.844151 -268.818217)
		(end 133.567678 -268.885416)
		(width 0.0889)
		(layer "B.Cu")
		(net "FM_S3M_CPU1_CPLD_CONFIG_N")
	)
	(arc
		(start 127.914146 -268.894052)
		(mid 127.726948 -268.944195)
		(end 127.53975 -268.894052)
		(width 0.0889)
		(layer "B.Cu")
		(net "FM_S3M_CPU1_CPLD_CONFIG_N")
	)
	(arc
		(start 128.47955 -268.894052)
		(mid 128.205351 -268.818217)
		(end 127.928878 -268.885416)
		(width 0.0889)
		(layer "B.Cu")
		(net "FM_S3M_CPU1_CPLD_CONFIG_N")
	)
	(arc
		(start 120.395492 -268.894052)
		(mid 120.208294 -268.944195)
		(end 120.021096 -268.894052)
		(width 0.0889)
		(layer "B.Cu")
		(net "FM_S3M_CPU1_CPLD_CONFIG_N")
	)
	(arc
		(start 132.23875 -268.894052)
		(mid 131.964551 -268.818217)
		(end 131.688078 -268.885416)
		(width 0.0889)
		(layer "B.Cu")
		(net "FM_S3M_CPU1_CPLD_CONFIG_N")
	)
	(arc
		(start 134.492746 -268.894052)
		(mid 134.305548 -268.944195)
		(end 134.11835 -268.894052)
		(width 0.0889)
		(layer "B.Cu")
		(net "FM_S3M_CPU1_CPLD_CONFIG_N")
	)
	(arc
		(start 127.53975 -268.894052)
		(mid 127.265551 -268.818217)
		(end 126.989078 -268.885416)
		(width 0.0889)
		(layer "B.Cu")
		(net "FM_S3M_CPU1_CPLD_CONFIG_N")
	)
	(arc
		(start 121.335546 -268.894052)
		(mid 121.148348 -268.944195)
		(end 120.96115 -268.894052)
		(width 0.0889)
		(layer "B.Cu")
		(net "FM_S3M_CPU1_CPLD_CONFIG_N")
	)
	(arc
		(start 122.275092 -268.894052)
		(mid 122.087894 -268.944195)
		(end 121.900696 -268.894052)
		(width 0.0889)
		(layer "B.Cu")
		(net "FM_S3M_CPU1_CPLD_CONFIG_N")
	)
	(arc
		(start 126.034546 -268.894052)
		(mid 125.847348 -268.944195)
		(end 125.66015 -268.894052)
		(width 0.0889)
		(layer "B.Cu")
		(net "FM_S3M_CPU1_CPLD_CONFIG_N")
	)
	(arc
		(start 129.41935 -268.894052)
		(mid 129.145151 -268.818217)
		(end 128.868678 -268.885416)
		(width 0.0889)
		(layer "B.Cu")
		(net "FM_S3M_CPU1_CPLD_CONFIG_N")
	)
	(arc
		(start 119.455692 -268.894052)
		(mid 119.268494 -268.944195)
		(end 119.081296 -268.894052)
		(width 0.0889)
		(layer "B.Cu")
		(net "FM_S3M_CPU1_CPLD_CONFIG_N")
	)
	(arc
		(start 123.214892 -268.894052)
		(mid 123.027694 -268.944195)
		(end 122.840496 -268.894052)
		(width 0.0889)
		(layer "B.Cu")
		(net "FM_S3M_CPU1_CPLD_CONFIG_N")
	)
	(arc
		(start 118.516146 -268.894052)
		(mid 118.328948 -268.944195)
		(end 118.14175 -268.894052)
		(width 0.0889)
		(layer "B.Cu")
		(net "FM_S3M_CPU1_CPLD_CONFIG_N")
	)
	(arc
		(start 124.72035 -268.894052)
		(mid 124.446151 -268.818217)
		(end 124.169678 -268.885416)
		(width 0.0889)
		(layer "B.Cu")
		(net "FM_S3M_CPU1_CPLD_CONFIG_N")
	)
	(arc
		(start 133.17855 -268.894052)
		(mid 132.895848 -268.818276)
		(end 132.613146 -268.894052)
		(width 0.0889)
		(layer "B.Cu")
		(net "FM_S3M_CPU1_CPLD_CONFIG_N")
	)
	(arc
		(start 131.673346 -268.894052)
		(mid 131.486148 -268.944195)
		(end 131.29895 -268.894052)
		(width 0.0889)
		(layer "B.Cu")
		(net "FM_S3M_CPU1_CPLD_CONFIG_N")
	)
	(arc
		(start 122.840496 -268.894052)
		(mid 122.557794 -268.818276)
		(end 122.275092 -268.894052)
		(width 0.0889)
		(layer "B.Cu")
		(net "FM_S3M_CPU1_CPLD_CONFIG_N")
	)
	(arc
		(start 123.78055 -268.894052)
		(mid 123.503737 -268.818182)
		(end 123.225306 -268.887956)
		(width 0.0889)
		(layer "B.Cu")
		(net "FM_S3M_CPU1_CPLD_CONFIG_N")
	)
	(arc
		(start 135.432546 -268.894052)
		(mid 135.245348 -268.944195)
		(end 135.05815 -268.894052)
		(width 0.0889)
		(layer "B.Cu")
		(net "FM_S3M_CPU1_CPLD_CONFIG_N")
	)
	(arc
		(start 120.006364 -268.885416)
		(mid 119.729889 -268.818096)
		(end 119.455692 -268.894052)
		(width 0.0889)
		(layer "B.Cu")
		(net "FM_S3M_CPU1_CPLD_CONFIG_N")
	)
	(arc
		(start 135.997696 -268.894052)
		(mid 135.721137 -268.818309)
		(end 135.44296 -268.887956)
		(width 0.0889)
		(layer "B.Cu")
		(net "FM_S3M_CPU1_CPLD_CONFIG_N")
	)
	(arc
		(start 128.853946 -268.894052)
		(mid 128.666748 -268.944195)
		(end 128.47955 -268.894052)
		(width 0.0889)
		(layer "B.Cu")
		(net "FM_S3M_CPU1_CPLD_CONFIG_N")
	)
	(arc
		(start 135.05815 -268.894052)
		(mid 134.783951 -268.818217)
		(end 134.507478 -268.885416)
		(width 0.0889)
		(layer "B.Cu")
		(net "FM_S3M_CPU1_CPLD_CONFIG_N")
	)
	(segment
		(start 350.762316 -272.103342)
		(end 350.762062 -272.103596)
		(width 0.12954)
		(layer "F.Cu")
		(net "FM_S3M_CPU0_LVC1_GPIO_4")
	)
	(segment
		(start 350.762062 -272.103596)
		(end 350.762062 -272.639282)
		(width 0.12954)
		(layer "F.Cu")
		(net "FM_S3M_CPU0_LVC1_GPIO_4")
	)
	(via
		(at 278.828246 -197.86727)
		(size 0.6604)
		(drill 0.3302)
		(layers "F.Cu" "B.Cu")
		(net "FM_S3M_CPU0_LVC1_GPIO_4")
	)
	(via
		(at 319.87109 -272.875502)
		(size 0.6604)
		(drill 0.3302)
		(layers "F.Cu" "B.Cu")
		(net "FM_S3M_CPU0_LVC1_GPIO_4")
	)
	(via
		(at 350.762062 -272.639282)
		(size 0.4572)
		(drill 0.2032)
		(layers "F.Cu" "B.Cu")
		(net "FM_S3M_CPU0_LVC1_GPIO_4")
	)
	(segment
		(start 306.655978 -274.53463)
		(end 304.248312 -274.53463)
		(width 0.12954)
		(layer "B.Cu")
		(net "FM_S3M_CPU0_LVC1_GPIO_4")
	)
	(segment
		(start 302.826928 -273.113246)
		(end 301.988474 -273.113246)
		(width 0.12954)
		(layer "B.Cu")
		(net "FM_S3M_CPU0_LVC1_GPIO_4")
	)
	(segment
		(start 338.742528 -272.32102)
		(end 338.732114 -272.314924)
		(width 0.0889)
		(layer "B.Cu")
		(net "FM_S3M_CPU0_LVC1_GPIO_4")
	)
	(segment
		(start 290.493958 -266.25169)
		(end 289.795458 -265.55319)
		(width 0.12954)
		(layer "B.Cu")
		(net "FM_S3M_CPU0_LVC1_GPIO_4")
	)
	(segment
		(start 275.927312 -194.290188)
		(end 276.147784 -194.069716)
		(width 0.12954)
		(layer "B.Cu")
		(net "FM_S3M_CPU0_LVC1_GPIO_4")
	)
	(segment
		(start 300.499018 -271.62379)
		(end 299.485558 -271.62379)
		(width 0.12954)
		(layer "B.Cu")
		(net "FM_S3M_CPU0_LVC1_GPIO_4")
	)
	(segment
		(start 351.074736 -272.639282)
		(end 351.13214 -272.581878)
		(width 0.0889)
		(layer "B.Cu")
		(net "FM_S3M_CPU0_LVC1_GPIO_4")
	)
	(segment
		(start 290.493958 -269.230602)
		(end 290.493958 -266.25169)
		(width 0.12954)
		(layer "B.Cu")
		(net "FM_S3M_CPU0_LVC1_GPIO_4")
	)
	(segment
		(start 331.596492 -272.55089)
		(end 331.27188 -272.875502)
		(width 0.12954)
		(layer "B.Cu")
		(net "FM_S3M_CPU0_LVC1_GPIO_4")
	)
	(segment
		(start 282.066238 -253.09957)
		(end 279.653238 -253.09957)
		(width 0.12954)
		(layer "B.Cu")
		(net "FM_S3M_CPU0_LVC1_GPIO_4")
	)
	(segment
		(start 293.105078 -270.95069)
		(end 292.214046 -270.95069)
		(width 0.12954)
		(layer "B.Cu")
		(net "FM_S3M_CPU0_LVC1_GPIO_4")
	)
	(segment
		(start 299.391578 -271.71777)
		(end 298.223178 -271.71777)
		(width 0.12954)
		(layer "B.Cu")
		(net "FM_S3M_CPU0_LVC1_GPIO_4")
	)
	(segment
		(start 344.936318 -272.314924)
		(end 344.925904 -272.32102)
		(width 0.0889)
		(layer "B.Cu")
		(net "FM_S3M_CPU0_LVC1_GPIO_4")
	)
	(segment
		(start 288.899092 -265.55319)
		(end 288.232088 -264.886186)
		(width 0.12954)
		(layer "B.Cu")
		(net "FM_S3M_CPU0_LVC1_GPIO_4")
	)
	(segment
		(start 350.574864 -272.314924)
		(end 350.560132 -272.32356)
		(width 0.0889)
		(layer "B.Cu")
		(net "FM_S3M_CPU0_LVC1_GPIO_4")
	)
	(segment
		(start 284.568392 -254.41275)
		(end 283.379418 -254.41275)
		(width 0.12954)
		(layer "B.Cu")
		(net "FM_S3M_CPU0_LVC1_GPIO_4")
	)
	(segment
		(start 340.237064 -272.314924)
		(end 340.222332 -272.32356)
		(width 0.0889)
		(layer "B.Cu")
		(net "FM_S3M_CPU0_LVC1_GPIO_4")
	)
	(segment
		(start 275.927312 -194.966336)
		(end 275.927312 -194.290188)
		(width 0.12954)
		(layer "B.Cu")
		(net "FM_S3M_CPU0_LVC1_GPIO_4")
	)
	(segment
		(start 297.981878 -271.95907)
		(end 295.835578 -271.95907)
		(width 0.12954)
		(layer "B.Cu")
		(net "FM_S3M_CPU0_LVC1_GPIO_4")
	)
	(segment
		(start 288.232088 -258.076446)
		(end 284.568392 -254.41275)
		(width 0.12954)
		(layer "B.Cu")
		(net "FM_S3M_CPU0_LVC1_GPIO_4")
	)
	(segment
		(start 343.056464 -272.314924)
		(end 343.041732 -272.32356)
		(width 0.0889)
		(layer "B.Cu")
		(net "FM_S3M_CPU0_LVC1_GPIO_4")
	)
	(segment
		(start 317.106046 -272.875502)
		(end 315.446918 -274.53463)
		(width 0.12954)
		(layer "B.Cu")
		(net "FM_S3M_CPU0_LVC1_GPIO_4")
	)
	(segment
		(start 319.87109 -272.875502)
		(end 317.106046 -272.875502)
		(width 0.12954)
		(layer "B.Cu")
		(net "FM_S3M_CPU0_LVC1_GPIO_4")
	)
	(segment
		(start 299.485558 -271.62379)
		(end 299.391578 -271.71777)
		(width 0.12954)
		(layer "B.Cu")
		(net "FM_S3M_CPU0_LVC1_GPIO_4")
	)
	(segment
		(start 335.526888 -272.50644)
		(end 335.482438 -272.55089)
		(width 0.12954)
		(layer "B.Cu")
		(net "FM_S3M_CPU0_LVC1_GPIO_4")
	)
	(segment
		(start 283.379418 -254.41275)
		(end 282.066238 -253.09957)
		(width 0.12954)
		(layer "B.Cu")
		(net "FM_S3M_CPU0_LVC1_GPIO_4")
	)
	(segment
		(start 278.828246 -197.86727)
		(end 275.927312 -194.966336)
		(width 0.12954)
		(layer "B.Cu")
		(net "FM_S3M_CPU0_LVC1_GPIO_4")
	)
	(segment
		(start 289.795458 -265.55319)
		(end 288.899092 -265.55319)
		(width 0.12954)
		(layer "B.Cu")
		(net "FM_S3M_CPU0_LVC1_GPIO_4")
	)
	(segment
		(start 304.248312 -274.53463)
		(end 302.826928 -273.113246)
		(width 0.12954)
		(layer "B.Cu")
		(net "FM_S3M_CPU0_LVC1_GPIO_4")
	)
	(segment
		(start 307.029358 -274.90801)
		(end 306.655978 -274.53463)
		(width 0.12954)
		(layer "B.Cu")
		(net "FM_S3M_CPU0_LVC1_GPIO_4")
	)
	(segment
		(start 292.214046 -270.95069)
		(end 290.493958 -269.230602)
		(width 0.12954)
		(layer "B.Cu")
		(net "FM_S3M_CPU0_LVC1_GPIO_4")
	)
	(segment
		(start 341.176864 -272.314924)
		(end 341.162132 -272.32356)
		(width 0.0889)
		(layer "B.Cu")
		(net "FM_S3M_CPU0_LVC1_GPIO_4")
	)
	(segment
		(start 345.321128 -272.32102)
		(end 345.310714 -272.314924)
		(width 0.0889)
		(layer "B.Cu")
		(net "FM_S3M_CPU0_LVC1_GPIO_4")
	)
	(segment
		(start 311.362598 -274.90801)
		(end 307.029358 -274.90801)
		(width 0.12954)
		(layer "B.Cu")
		(net "FM_S3M_CPU0_LVC1_GPIO_4")
	)
	(segment
		(start 279.005538 -198.044562)
		(end 278.828246 -197.86727)
		(width 0.12954)
		(layer "B.Cu")
		(net "FM_S3M_CPU0_LVC1_GPIO_4")
	)
	(segment
		(start 337.417664 -272.314924)
		(end 337.40725 -272.32102)
		(width 0.0889)
		(layer "B.Cu")
		(net "FM_S3M_CPU0_LVC1_GPIO_4")
	)
	(segment
		(start 335.482438 -272.55089)
		(end 331.596492 -272.55089)
		(width 0.12954)
		(layer "B.Cu")
		(net "FM_S3M_CPU0_LVC1_GPIO_4")
	)
	(segment
		(start 337.802474 -272.32102)
		(end 337.79206 -272.314924)
		(width 0.0889)
		(layer "B.Cu")
		(net "FM_S3M_CPU0_LVC1_GPIO_4")
	)
	(segment
		(start 295.835578 -271.95907)
		(end 295.546018 -271.66951)
		(width 0.12954)
		(layer "B.Cu")
		(net "FM_S3M_CPU0_LVC1_GPIO_4")
	)
	(segment
		(start 343.996264 -272.314924)
		(end 343.981532 -272.32356)
		(width 0.0889)
		(layer "B.Cu")
		(net "FM_S3M_CPU0_LVC1_GPIO_4")
	)
	(segment
		(start 295.546018 -271.66951)
		(end 293.823898 -271.66951)
		(width 0.12954)
		(layer "B.Cu")
		(net "FM_S3M_CPU0_LVC1_GPIO_4")
	)
	(segment
		(start 279.653238 -253.09957)
		(end 279.005538 -252.45187)
		(width 0.12954)
		(layer "B.Cu")
		(net "FM_S3M_CPU0_LVC1_GPIO_4")
	)
	(segment
		(start 288.232088 -264.886186)
		(end 288.232088 -258.076446)
		(width 0.12954)
		(layer "B.Cu")
		(net "FM_S3M_CPU0_LVC1_GPIO_4")
	)
	(segment
		(start 342.116664 -272.314924)
		(end 342.101932 -272.32356)
		(width 0.0889)
		(layer "B.Cu")
		(net "FM_S3M_CPU0_LVC1_GPIO_4")
	)
	(segment
		(start 349.635064 -272.314924)
		(end 349.620332 -272.32356)
		(width 0.0889)
		(layer "B.Cu")
		(net "FM_S3M_CPU0_LVC1_GPIO_4")
	)
	(segment
		(start 331.27188 -272.875502)
		(end 319.87109 -272.875502)
		(width 0.12954)
		(layer "B.Cu")
		(net "FM_S3M_CPU0_LVC1_GPIO_4")
	)
	(segment
		(start 301.988474 -273.113246)
		(end 300.499018 -271.62379)
		(width 0.12954)
		(layer "B.Cu")
		(net "FM_S3M_CPU0_LVC1_GPIO_4")
	)
	(segment
		(start 346.815664 -272.314924)
		(end 346.800932 -272.32356)
		(width 0.0889)
		(layer "B.Cu")
		(net "FM_S3M_CPU0_LVC1_GPIO_4")
	)
	(segment
		(start 293.823898 -271.66951)
		(end 293.105078 -270.95069)
		(width 0.12954)
		(layer "B.Cu")
		(net "FM_S3M_CPU0_LVC1_GPIO_4")
	)
	(segment
		(start 279.005538 -252.45187)
		(end 279.005538 -198.044562)
		(width 0.12954)
		(layer "B.Cu")
		(net "FM_S3M_CPU0_LVC1_GPIO_4")
	)
	(segment
		(start 315.446918 -274.53463)
		(end 311.735978 -274.53463)
		(width 0.12954)
		(layer "B.Cu")
		(net "FM_S3M_CPU0_LVC1_GPIO_4")
	)
	(segment
		(start 347.755464 -272.314924)
		(end 347.740732 -272.32356)
		(width 0.0889)
		(layer "B.Cu")
		(net "FM_S3M_CPU0_LVC1_GPIO_4")
	)
	(segment
		(start 350.762062 -272.639282)
		(end 351.074736 -272.639282)
		(width 0.0889)
		(layer "B.Cu")
		(net "FM_S3M_CPU0_LVC1_GPIO_4")
	)
	(segment
		(start 311.735978 -274.53463)
		(end 311.362598 -274.90801)
		(width 0.12954)
		(layer "B.Cu")
		(net "FM_S3M_CPU0_LVC1_GPIO_4")
	)
	(segment
		(start 348.695264 -272.314924)
		(end 348.680532 -272.32356)
		(width 0.0889)
		(layer "B.Cu")
		(net "FM_S3M_CPU0_LVC1_GPIO_4")
	)
	(segment
		(start 335.764124 -272.50644)
		(end 335.526888 -272.50644)
		(width 0.12954)
		(layer "B.Cu")
		(net "FM_S3M_CPU0_LVC1_GPIO_4")
	)
	(segment
		(start 298.223178 -271.71777)
		(end 297.981878 -271.95907)
		(width 0.12954)
		(layer "B.Cu")
		(net "FM_S3M_CPU0_LVC1_GPIO_4")
	)
	(arc
		(start 342.49106 -272.314924)
		(mid 342.303862 -272.264781)
		(end 342.116664 -272.314924)
		(width 0.0889)
		(layer "B.Cu")
		(net "FM_S3M_CPU0_LVC1_GPIO_4")
	)
	(arc
		(start 342.101932 -272.32356)
		(mid 341.825491 -272.390726)
		(end 341.55126 -272.314924)
		(width 0.0889)
		(layer "B.Cu")
		(net "FM_S3M_CPU0_LVC1_GPIO_4")
	)
	(arc
		(start 350.560132 -272.32356)
		(mid 350.283691 -272.390726)
		(end 350.00946 -272.314924)
		(width 0.0889)
		(layer "B.Cu")
		(net "FM_S3M_CPU0_LVC1_GPIO_4")
	)
	(arc
		(start 345.310714 -272.314924)
		(mid 345.123516 -272.264781)
		(end 344.936318 -272.314924)
		(width 0.0889)
		(layer "B.Cu")
		(net "FM_S3M_CPU0_LVC1_GPIO_4")
	)
	(arc
		(start 343.981532 -272.32356)
		(mid 343.705091 -272.390726)
		(end 343.43086 -272.314924)
		(width 0.0889)
		(layer "B.Cu")
		(net "FM_S3M_CPU0_LVC1_GPIO_4")
	)
	(arc
		(start 340.222332 -272.32356)
		(mid 339.945891 -272.390726)
		(end 339.67166 -272.314924)
		(width 0.0889)
		(layer "B.Cu")
		(net "FM_S3M_CPU0_LVC1_GPIO_4")
	)
	(arc
		(start 349.620332 -272.32356)
		(mid 349.343891 -272.390726)
		(end 349.06966 -272.314924)
		(width 0.0889)
		(layer "B.Cu")
		(net "FM_S3M_CPU0_LVC1_GPIO_4")
	)
	(arc
		(start 338.732114 -272.314924)
		(mid 338.544916 -272.264781)
		(end 338.357718 -272.314924)
		(width 0.0889)
		(layer "B.Cu")
		(net "FM_S3M_CPU0_LVC1_GPIO_4")
	)
	(arc
		(start 351.13214 -272.581878)
		(mid 350.923857 -272.301532)
		(end 350.574864 -272.314924)
		(width 0.0889)
		(layer "B.Cu")
		(net "FM_S3M_CPU0_LVC1_GPIO_4")
	)
	(arc
		(start 343.43086 -272.314924)
		(mid 343.243662 -272.264781)
		(end 343.056464 -272.314924)
		(width 0.0889)
		(layer "B.Cu")
		(net "FM_S3M_CPU0_LVC1_GPIO_4")
	)
	(arc
		(start 347.740732 -272.32356)
		(mid 347.464291 -272.390726)
		(end 347.19006 -272.314924)
		(width 0.0889)
		(layer "B.Cu")
		(net "FM_S3M_CPU0_LVC1_GPIO_4")
	)
	(arc
		(start 337.79206 -272.314924)
		(mid 337.604862 -272.264781)
		(end 337.417664 -272.314924)
		(width 0.0889)
		(layer "B.Cu")
		(net "FM_S3M_CPU0_LVC1_GPIO_4")
	)
	(arc
		(start 343.041732 -272.32356)
		(mid 342.765291 -272.390726)
		(end 342.49106 -272.314924)
		(width 0.0889)
		(layer "B.Cu")
		(net "FM_S3M_CPU0_LVC1_GPIO_4")
	)
	(arc
		(start 344.925904 -272.32102)
		(mid 344.647472 -272.390834)
		(end 344.37066 -272.314924)
		(width 0.0889)
		(layer "B.Cu")
		(net "FM_S3M_CPU0_LVC1_GPIO_4")
	)
	(arc
		(start 349.06966 -272.314924)
		(mid 348.882462 -272.264781)
		(end 348.695264 -272.314924)
		(width 0.0889)
		(layer "B.Cu")
		(net "FM_S3M_CPU0_LVC1_GPIO_4")
	)
	(arc
		(start 341.55126 -272.314924)
		(mid 341.364062 -272.264781)
		(end 341.176864 -272.314924)
		(width 0.0889)
		(layer "B.Cu")
		(net "FM_S3M_CPU0_LVC1_GPIO_4")
	)
	(arc
		(start 337.40725 -272.32102)
		(mid 337.129072 -272.390712)
		(end 336.852514 -272.314924)
		(width 0.0889)
		(layer "B.Cu")
		(net "FM_S3M_CPU0_LVC1_GPIO_4")
	)
	(arc
		(start 339.67166 -272.314924)
		(mid 339.484462 -272.264781)
		(end 339.297264 -272.314924)
		(width 0.0889)
		(layer "B.Cu")
		(net "FM_S3M_CPU0_LVC1_GPIO_4")
	)
	(arc
		(start 341.162132 -272.32356)
		(mid 340.885691 -272.390726)
		(end 340.61146 -272.314924)
		(width 0.0889)
		(layer "B.Cu")
		(net "FM_S3M_CPU0_LVC1_GPIO_4")
	)
	(arc
		(start 348.12986 -272.314924)
		(mid 347.942662 -272.264781)
		(end 347.755464 -272.314924)
		(width 0.0889)
		(layer "B.Cu")
		(net "FM_S3M_CPU0_LVC1_GPIO_4")
	)
	(arc
		(start 350.00946 -272.314924)
		(mid 349.822262 -272.264781)
		(end 349.635064 -272.314924)
		(width 0.0889)
		(layer "B.Cu")
		(net "FM_S3M_CPU0_LVC1_GPIO_4")
	)
	(arc
		(start 346.25026 -272.314924)
		(mid 346.063062 -272.264781)
		(end 345.875864 -272.314924)
		(width 0.0889)
		(layer "B.Cu")
		(net "FM_S3M_CPU0_LVC1_GPIO_4")
	)
	(arc
		(start 338.357718 -272.314924)
		(mid 338.080905 -272.39076)
		(end 337.802474 -272.32102)
		(width 0.0889)
		(layer "B.Cu")
		(net "FM_S3M_CPU0_LVC1_GPIO_4")
	)
	(arc
		(start 336.478118 -272.314924)
		(mid 336.133744 -272.457751)
		(end 335.764124 -272.50644)
		(width 0.0889)
		(layer "B.Cu")
		(net "FM_S3M_CPU0_LVC1_GPIO_4")
	)
	(arc
		(start 347.19006 -272.314924)
		(mid 347.002862 -272.264781)
		(end 346.815664 -272.314924)
		(width 0.0889)
		(layer "B.Cu")
		(net "FM_S3M_CPU0_LVC1_GPIO_4")
	)
	(arc
		(start 340.61146 -272.314924)
		(mid 340.424262 -272.264781)
		(end 340.237064 -272.314924)
		(width 0.0889)
		(layer "B.Cu")
		(net "FM_S3M_CPU0_LVC1_GPIO_4")
	)
	(arc
		(start 346.800932 -272.32356)
		(mid 346.524491 -272.390726)
		(end 346.25026 -272.314924)
		(width 0.0889)
		(layer "B.Cu")
		(net "FM_S3M_CPU0_LVC1_GPIO_4")
	)
	(arc
		(start 344.37066 -272.314924)
		(mid 344.183462 -272.264781)
		(end 343.996264 -272.314924)
		(width 0.0889)
		(layer "B.Cu")
		(net "FM_S3M_CPU0_LVC1_GPIO_4")
	)
	(arc
		(start 345.875864 -272.314924)
		(mid 345.599305 -272.390633)
		(end 345.321128 -272.32102)
		(width 0.0889)
		(layer "B.Cu")
		(net "FM_S3M_CPU0_LVC1_GPIO_4")
	)
	(arc
		(start 336.852514 -272.314924)
		(mid 336.665316 -272.264781)
		(end 336.478118 -272.314924)
		(width 0.0889)
		(layer "B.Cu")
		(net "FM_S3M_CPU0_LVC1_GPIO_4")
	)
	(arc
		(start 348.680532 -272.32356)
		(mid 348.404091 -272.390726)
		(end 348.12986 -272.314924)
		(width 0.0889)
		(layer "B.Cu")
		(net "FM_S3M_CPU0_LVC1_GPIO_4")
	)
	(arc
		(start 339.297264 -272.314924)
		(mid 339.020705 -272.390633)
		(end 338.742528 -272.32102)
		(width 0.0889)
		(layer "B.Cu")
		(net "FM_S3M_CPU0_LVC1_GPIO_4")
	)
	(segment
		(start 351.231962 -271.289272)
		(end 351.231962 -271.824958)
		(width 0.12954)
		(layer "F.Cu")
		(net "FM_S3M_CPU0_LVC1_GPIO_3")
	)
	(segment
		(start 351.231962 -271.824958)
		(end 351.232216 -271.825212)
		(width 0.12954)
		(layer "F.Cu")
		(net "FM_S3M_CPU0_LVC1_GPIO_3")
	)
	(via
		(at 351.232216 -271.825212)
		(size 0.4572)
		(drill 0.2032)
		(layers "F.Cu" "B.Cu")
		(net "FM_S3M_CPU0_LVC1_GPIO_3")
	)
	(via
		(at 320.126614 -271.08912)
		(size 0.6604)
		(drill 0.3302)
		(layers "F.Cu" "B.Cu")
		(net "FM_S3M_CPU0_LVC1_GPIO_3")
	)
	(segment
		(start 290.090098 -258.22529)
		(end 287.553146 -255.688338)
		(width 0.12954)
		(layer "B.Cu")
		(net "FM_S3M_CPU0_LVC1_GPIO_3")
	)
	(segment
		(start 335.273142 -271.08912)
		(end 334.630268 -271.08912)
		(width 0.12954)
		(layer "B.Cu")
		(net "FM_S3M_CPU0_LVC1_GPIO_3")
	)
	(segment
		(start 340.237064 -271.335754)
		(end 340.222332 -271.327118)
		(width 0.0889)
		(layer "B.Cu")
		(net "FM_S3M_CPU0_LVC1_GPIO_3")
	)
	(segment
		(start 307.054758 -272.36039)
		(end 305.563778 -272.36039)
		(width 0.12954)
		(layer "B.Cu")
		(net "FM_S3M_CPU0_LVC1_GPIO_3")
	)
	(segment
		(start 281.58567 -195.212462)
		(end 281.41803 -195.212462)
		(width 0.12954)
		(layer "B.Cu")
		(net "FM_S3M_CPU0_LVC1_GPIO_3")
	)
	(segment
		(start 291.347398 -265.06043)
		(end 290.090098 -263.80313)
		(width 0.12954)
		(layer "B.Cu")
		(net "FM_S3M_CPU0_LVC1_GPIO_3")
	)
	(segment
		(start 281.100784 -194.895216)
		(end 281.100784 -194.069716)
		(width 0.12954)
		(layer "B.Cu")
		(net "FM_S3M_CPU0_LVC1_GPIO_3")
	)
	(segment
		(start 316.613794 -271.089374)
		(end 315.195458 -272.50771)
		(width 0.12954)
		(layer "B.Cu")
		(net "FM_S3M_CPU0_LVC1_GPIO_3")
	)
	(segment
		(start 290.090098 -263.80313)
		(end 290.090098 -258.22529)
		(width 0.12954)
		(layer "B.Cu")
		(net "FM_S3M_CPU0_LVC1_GPIO_3")
	)
	(segment
		(start 344.936064 -271.335754)
		(end 344.921332 -271.327118)
		(width 0.0889)
		(layer "B.Cu")
		(net "FM_S3M_CPU0_LVC1_GPIO_3")
	)
	(segment
		(start 302.835818 -270.89481)
		(end 302.124872 -270.89481)
		(width 0.12954)
		(layer "B.Cu")
		(net "FM_S3M_CPU0_LVC1_GPIO_3")
	)
	(segment
		(start 335.46034 -271.276318)
		(end 335.273142 -271.08912)
		(width 0.0889)
		(layer "B.Cu")
		(net "FM_S3M_CPU0_LVC1_GPIO_3")
	)
	(segment
		(start 305.563778 -272.36039)
		(end 305.200558 -271.99717)
		(width 0.12954)
		(layer "B.Cu")
		(net "FM_S3M_CPU0_LVC1_GPIO_3")
	)
	(segment
		(start 341.176864 -271.335754)
		(end 341.162132 -271.327118)
		(width 0.0889)
		(layer "B.Cu")
		(net "FM_S3M_CPU0_LVC1_GPIO_3")
	)
	(segment
		(start 343.996264 -271.335754)
		(end 343.981532 -271.327118)
		(width 0.0889)
		(layer "B.Cu")
		(net "FM_S3M_CPU0_LVC1_GPIO_3")
	)
	(segment
		(start 320.126614 -271.08912)
		(end 318.470026 -271.08912)
		(width 0.12954)
		(layer "B.Cu")
		(net "FM_S3M_CPU0_LVC1_GPIO_3")
	)
	(segment
		(start 293.564818 -266.27201)
		(end 293.293038 -266.00023)
		(width 0.12954)
		(layer "B.Cu")
		(net "FM_S3M_CPU0_LVC1_GPIO_3")
	)
	(segment
		(start 343.056464 -271.335754)
		(end 343.04605 -271.329658)
		(width 0.0889)
		(layer "B.Cu")
		(net "FM_S3M_CPU0_LVC1_GPIO_3")
	)
	(segment
		(start 348.695518 -271.335754)
		(end 348.685104 -271.329658)
		(width 0.0889)
		(layer "B.Cu")
		(net "FM_S3M_CPU0_LVC1_GPIO_3")
	)
	(segment
		(start 291.664898 -265.06043)
		(end 291.347398 -265.06043)
		(width 0.12954)
		(layer "B.Cu")
		(net "FM_S3M_CPU0_LVC1_GPIO_3")
	)
	(segment
		(start 292.604698 -266.00023)
		(end 291.664898 -265.06043)
		(width 0.12954)
		(layer "B.Cu")
		(net "FM_S3M_CPU0_LVC1_GPIO_3")
	)
	(segment
		(start 342.116918 -271.335754)
		(end 342.106504 -271.329658)
		(width 0.0889)
		(layer "B.Cu")
		(net "FM_S3M_CPU0_LVC1_GPIO_3")
	)
	(segment
		(start 282.602432 -252.308614)
		(end 282.602432 -196.229224)
		(width 0.12954)
		(layer "B.Cu")
		(net "FM_S3M_CPU0_LVC1_GPIO_3")
	)
	(segment
		(start 351.232216 -271.825212)
		(end 350.919542 -271.825212)
		(width 0.0889)
		(layer "B.Cu")
		(net "FM_S3M_CPU0_LVC1_GPIO_3")
	)
	(segment
		(start 287.15208 -255.688338)
		(end 284.90164 -253.437898)
		(width 0.12954)
		(layer "B.Cu")
		(net "FM_S3M_CPU0_LVC1_GPIO_3")
	)
	(segment
		(start 305.200558 -271.99717)
		(end 303.938178 -271.99717)
		(width 0.12954)
		(layer "B.Cu")
		(net "FM_S3M_CPU0_LVC1_GPIO_3")
	)
	(segment
		(start 294.303958 -269.16253)
		(end 293.564818 -268.42339)
		(width 0.12954)
		(layer "B.Cu")
		(net "FM_S3M_CPU0_LVC1_GPIO_3")
	)
	(segment
		(start 350.919542 -271.825212)
		(end 350.853756 -271.759426)
		(width 0.0889)
		(layer "B.Cu")
		(net "FM_S3M_CPU0_LVC1_GPIO_3")
	)
	(segment
		(start 334.630268 -271.08912)
		(end 334.456532 -271.262856)
		(width 0.12954)
		(layer "B.Cu")
		(net "FM_S3M_CPU0_LVC1_GPIO_3")
	)
	(segment
		(start 299.771816 -269.519908)
		(end 299.366178 -269.11427)
		(width 0.12954)
		(layer "B.Cu")
		(net "FM_S3M_CPU0_LVC1_GPIO_3")
	)
	(segment
		(start 307.608478 -272.91411)
		(end 307.054758 -272.36039)
		(width 0.12954)
		(layer "B.Cu")
		(net "FM_S3M_CPU0_LVC1_GPIO_3")
	)
	(segment
		(start 347.755464 -271.335754)
		(end 347.740732 -271.327118)
		(width 0.0889)
		(layer "B.Cu")
		(net "FM_S3M_CPU0_LVC1_GPIO_3")
	)
	(segment
		(start 311.045098 -272.50771)
		(end 310.638698 -272.91411)
		(width 0.12954)
		(layer "B.Cu")
		(net "FM_S3M_CPU0_LVC1_GPIO_3")
	)
	(segment
		(start 293.564818 -268.42339)
		(end 293.564818 -266.27201)
		(width 0.12954)
		(layer "B.Cu")
		(net "FM_S3M_CPU0_LVC1_GPIO_3")
	)
	(segment
		(start 283.731716 -253.437898)
		(end 282.602432 -252.308614)
		(width 0.12954)
		(layer "B.Cu")
		(net "FM_S3M_CPU0_LVC1_GPIO_3")
	)
	(segment
		(start 299.366178 -269.11427)
		(end 295.914572 -269.11427)
		(width 0.12954)
		(layer "B.Cu")
		(net "FM_S3M_CPU0_LVC1_GPIO_3")
	)
	(segment
		(start 295.914572 -269.11427)
		(end 295.866312 -269.16253)
		(width 0.12954)
		(layer "B.Cu")
		(net "FM_S3M_CPU0_LVC1_GPIO_3")
	)
	(segment
		(start 295.866312 -269.16253)
		(end 294.303958 -269.16253)
		(width 0.12954)
		(layer "B.Cu")
		(net "FM_S3M_CPU0_LVC1_GPIO_3")
	)
	(segment
		(start 281.41803 -195.212462)
		(end 281.100784 -194.895216)
		(width 0.12954)
		(layer "B.Cu")
		(net "FM_S3M_CPU0_LVC1_GPIO_3")
	)
	(segment
		(start 318.470026 -271.08912)
		(end 318.470026 -271.089374)
		(width 0.12954)
		(layer "B.Cu")
		(net "FM_S3M_CPU0_LVC1_GPIO_3")
	)
	(segment
		(start 310.638698 -272.91411)
		(end 307.608478 -272.91411)
		(width 0.12954)
		(layer "B.Cu")
		(net "FM_S3M_CPU0_LVC1_GPIO_3")
	)
	(segment
		(start 287.553146 -255.688338)
		(end 287.15208 -255.688338)
		(width 0.12954)
		(layer "B.Cu")
		(net "FM_S3M_CPU0_LVC1_GPIO_3")
	)
	(segment
		(start 346.815664 -271.335754)
		(end 346.800932 -271.327118)
		(width 0.0889)
		(layer "B.Cu")
		(net "FM_S3M_CPU0_LVC1_GPIO_3")
	)
	(segment
		(start 337.417664 -271.335754)
		(end 337.402932 -271.327118)
		(width 0.0889)
		(layer "B.Cu")
		(net "FM_S3M_CPU0_LVC1_GPIO_3")
	)
	(segment
		(start 302.124872 -270.89481)
		(end 300.74997 -269.519908)
		(width 0.12954)
		(layer "B.Cu")
		(net "FM_S3M_CPU0_LVC1_GPIO_3")
	)
	(segment
		(start 334.456532 -271.262856)
		(end 328.286872 -271.262856)
		(width 0.12954)
		(layer "B.Cu")
		(net "FM_S3M_CPU0_LVC1_GPIO_3")
	)
	(segment
		(start 328.286872 -271.262856)
		(end 328.113136 -271.08912)
		(width 0.12954)
		(layer "B.Cu")
		(net "FM_S3M_CPU0_LVC1_GPIO_3")
	)
	(segment
		(start 328.113136 -271.08912)
		(end 320.126614 -271.08912)
		(width 0.12954)
		(layer "B.Cu")
		(net "FM_S3M_CPU0_LVC1_GPIO_3")
	)
	(segment
		(start 300.74997 -269.519908)
		(end 299.771816 -269.519908)
		(width 0.12954)
		(layer "B.Cu")
		(net "FM_S3M_CPU0_LVC1_GPIO_3")
	)
	(segment
		(start 282.602432 -196.229224)
		(end 281.58567 -195.212462)
		(width 0.12954)
		(layer "B.Cu")
		(net "FM_S3M_CPU0_LVC1_GPIO_3")
	)
	(segment
		(start 318.470026 -271.089374)
		(end 316.613794 -271.089374)
		(width 0.12954)
		(layer "B.Cu")
		(net "FM_S3M_CPU0_LVC1_GPIO_3")
	)
	(segment
		(start 281.100784 -194.069716)
		(end 280.110184 -194.069716)
		(width 0.12954)
		(layer "B.Cu")
		(net "FM_S3M_CPU0_LVC1_GPIO_3")
	)
	(segment
		(start 315.195458 -272.50771)
		(end 311.045098 -272.50771)
		(width 0.12954)
		(layer "B.Cu")
		(net "FM_S3M_CPU0_LVC1_GPIO_3")
	)
	(segment
		(start 293.293038 -266.00023)
		(end 292.604698 -266.00023)
		(width 0.12954)
		(layer "B.Cu")
		(net "FM_S3M_CPU0_LVC1_GPIO_3")
	)
	(segment
		(start 303.938178 -271.99717)
		(end 302.835818 -270.89481)
		(width 0.12954)
		(layer "B.Cu")
		(net "FM_S3M_CPU0_LVC1_GPIO_3")
	)
	(segment
		(start 284.90164 -253.437898)
		(end 283.731716 -253.437898)
		(width 0.12954)
		(layer "B.Cu")
		(net "FM_S3M_CPU0_LVC1_GPIO_3")
	)
	(arc
		(start 344.37066 -271.335754)
		(mid 344.183462 -271.385897)
		(end 343.996264 -271.335754)
		(width 0.0889)
		(layer "B.Cu")
		(net "FM_S3M_CPU0_LVC1_GPIO_3")
	)
	(arc
		(start 342.106504 -271.329658)
		(mid 341.828072 -271.259812)
		(end 341.55126 -271.335754)
		(width 0.0889)
		(layer "B.Cu")
		(net "FM_S3M_CPU0_LVC1_GPIO_3")
	)
	(arc
		(start 343.981532 -271.327118)
		(mid 343.705057 -271.259798)
		(end 343.43086 -271.335754)
		(width 0.0889)
		(layer "B.Cu")
		(net "FM_S3M_CPU0_LVC1_GPIO_3")
	)
	(arc
		(start 343.04605 -271.329658)
		(mid 342.767872 -271.259935)
		(end 342.491314 -271.335754)
		(width 0.0889)
		(layer "B.Cu")
		(net "FM_S3M_CPU0_LVC1_GPIO_3")
	)
	(arc
		(start 338.73186 -271.335754)
		(mid 338.544662 -271.385897)
		(end 338.357464 -271.335754)
		(width 0.0889)
		(layer "B.Cu")
		(net "FM_S3M_CPU0_LVC1_GPIO_3")
	)
	(arc
		(start 349.635318 -271.335754)
		(mid 349.352616 -271.259978)
		(end 349.069914 -271.335754)
		(width 0.0889)
		(layer "B.Cu")
		(net "FM_S3M_CPU0_LVC1_GPIO_3")
	)
	(arc
		(start 335.91246 -271.335754)
		(mid 335.725262 -271.385897)
		(end 335.538064 -271.335754)
		(width 0.0889)
		(layer "B.Cu")
		(net "FM_S3M_CPU0_LVC1_GPIO_3")
	)
	(arc
		(start 342.491314 -271.335754)
		(mid 342.304116 -271.385897)
		(end 342.116918 -271.335754)
		(width 0.0889)
		(layer "B.Cu")
		(net "FM_S3M_CPU0_LVC1_GPIO_3")
	)
	(arc
		(start 349.069914 -271.335754)
		(mid 348.882716 -271.385897)
		(end 348.695518 -271.335754)
		(width 0.0889)
		(layer "B.Cu")
		(net "FM_S3M_CPU0_LVC1_GPIO_3")
	)
	(arc
		(start 339.67166 -271.335754)
		(mid 339.484462 -271.385897)
		(end 339.297264 -271.335754)
		(width 0.0889)
		(layer "B.Cu")
		(net "FM_S3M_CPU0_LVC1_GPIO_3")
	)
	(arc
		(start 347.740732 -271.327118)
		(mid 347.464257 -271.259798)
		(end 347.19006 -271.335754)
		(width 0.0889)
		(layer "B.Cu")
		(net "FM_S3M_CPU0_LVC1_GPIO_3")
	)
	(arc
		(start 339.297264 -271.335754)
		(mid 339.014562 -271.259978)
		(end 338.73186 -271.335754)
		(width 0.0889)
		(layer "B.Cu")
		(net "FM_S3M_CPU0_LVC1_GPIO_3")
	)
	(arc
		(start 348.12986 -271.335754)
		(mid 347.942662 -271.385897)
		(end 347.755464 -271.335754)
		(width 0.0889)
		(layer "B.Cu")
		(net "FM_S3M_CPU0_LVC1_GPIO_3")
	)
	(arc
		(start 350.853756 -271.759426)
		(mid 350.545948 -271.320086)
		(end 350.009714 -271.335754)
		(width 0.0889)
		(layer "B.Cu")
		(net "FM_S3M_CPU0_LVC1_GPIO_3")
	)
	(arc
		(start 340.222332 -271.327118)
		(mid 339.945857 -271.259798)
		(end 339.67166 -271.335754)
		(width 0.0889)
		(layer "B.Cu")
		(net "FM_S3M_CPU0_LVC1_GPIO_3")
	)
	(arc
		(start 350.009714 -271.335754)
		(mid 349.822516 -271.385897)
		(end 349.635318 -271.335754)
		(width 0.0889)
		(layer "B.Cu")
		(net "FM_S3M_CPU0_LVC1_GPIO_3")
	)
	(arc
		(start 347.19006 -271.335754)
		(mid 347.002862 -271.385897)
		(end 346.815664 -271.335754)
		(width 0.0889)
		(layer "B.Cu")
		(net "FM_S3M_CPU0_LVC1_GPIO_3")
	)
	(arc
		(start 345.31046 -271.335754)
		(mid 345.123262 -271.385897)
		(end 344.936064 -271.335754)
		(width 0.0889)
		(layer "B.Cu")
		(net "FM_S3M_CPU0_LVC1_GPIO_3")
	)
	(arc
		(start 336.477864 -271.335754)
		(mid 336.195162 -271.259978)
		(end 335.91246 -271.335754)
		(width 0.0889)
		(layer "B.Cu")
		(net "FM_S3M_CPU0_LVC1_GPIO_3")
	)
	(arc
		(start 343.43086 -271.335754)
		(mid 343.243662 -271.385897)
		(end 343.056464 -271.335754)
		(width 0.0889)
		(layer "B.Cu")
		(net "FM_S3M_CPU0_LVC1_GPIO_3")
	)
	(arc
		(start 340.61146 -271.335754)
		(mid 340.424262 -271.385897)
		(end 340.237064 -271.335754)
		(width 0.0889)
		(layer "B.Cu")
		(net "FM_S3M_CPU0_LVC1_GPIO_3")
	)
	(arc
		(start 348.685104 -271.329658)
		(mid 348.406672 -271.259812)
		(end 348.12986 -271.335754)
		(width 0.0889)
		(layer "B.Cu")
		(net "FM_S3M_CPU0_LVC1_GPIO_3")
	)
	(arc
		(start 341.55126 -271.335754)
		(mid 341.364062 -271.385897)
		(end 341.176864 -271.335754)
		(width 0.0889)
		(layer "B.Cu")
		(net "FM_S3M_CPU0_LVC1_GPIO_3")
	)
	(arc
		(start 346.800932 -271.327118)
		(mid 346.524457 -271.259798)
		(end 346.25026 -271.335754)
		(width 0.0889)
		(layer "B.Cu")
		(net "FM_S3M_CPU0_LVC1_GPIO_3")
	)
	(arc
		(start 338.357464 -271.335754)
		(mid 338.074762 -271.259978)
		(end 337.79206 -271.335754)
		(width 0.0889)
		(layer "B.Cu")
		(net "FM_S3M_CPU0_LVC1_GPIO_3")
	)
	(arc
		(start 341.162132 -271.327118)
		(mid 340.885657 -271.259798)
		(end 340.61146 -271.335754)
		(width 0.0889)
		(layer "B.Cu")
		(net "FM_S3M_CPU0_LVC1_GPIO_3")
	)
	(arc
		(start 336.85226 -271.335754)
		(mid 336.665062 -271.385897)
		(end 336.477864 -271.335754)
		(width 0.0889)
		(layer "B.Cu")
		(net "FM_S3M_CPU0_LVC1_GPIO_3")
	)
	(arc
		(start 337.402932 -271.327118)
		(mid 337.126457 -271.259798)
		(end 336.85226 -271.335754)
		(width 0.0889)
		(layer "B.Cu")
		(net "FM_S3M_CPU0_LVC1_GPIO_3")
	)
	(arc
		(start 335.538064 -271.335754)
		(mid 335.497255 -271.308582)
		(end 335.46034 -271.276318)
		(width 0.0889)
		(layer "B.Cu")
		(net "FM_S3M_CPU0_LVC1_GPIO_3")
	)
	(arc
		(start 344.921332 -271.327118)
		(mid 344.644857 -271.259798)
		(end 344.37066 -271.335754)
		(width 0.0889)
		(layer "B.Cu")
		(net "FM_S3M_CPU0_LVC1_GPIO_3")
	)
	(arc
		(start 337.79206 -271.335754)
		(mid 337.604862 -271.385897)
		(end 337.417664 -271.335754)
		(width 0.0889)
		(layer "B.Cu")
		(net "FM_S3M_CPU0_LVC1_GPIO_3")
	)
	(arc
		(start 346.25026 -271.335754)
		(mid 346.063062 -271.385897)
		(end 345.875864 -271.335754)
		(width 0.0889)
		(layer "B.Cu")
		(net "FM_S3M_CPU0_LVC1_GPIO_3")
	)
	(arc
		(start 345.875864 -271.335754)
		(mid 345.593162 -271.259978)
		(end 345.31046 -271.335754)
		(width 0.0889)
		(layer "B.Cu")
		(net "FM_S3M_CPU0_LVC1_GPIO_3")
	)
	(segment
		(start 350.292162 -271.289272)
		(end 350.292416 -271.289526)
		(width 0.12954)
		(layer "F.Cu")
		(net "FM_S3M_CPU0_LVC1_GPIO_2")
	)
	(segment
		(start 350.292416 -271.289526)
		(end 350.292416 -271.825212)
		(width 0.12954)
		(layer "F.Cu")
		(net "FM_S3M_CPU0_LVC1_GPIO_2")
	)
	(via
		(at 327.286366 -271.64284)
		(size 0.6604)
		(drill 0.3302)
		(layers "F.Cu" "B.Cu")
		(net "FM_S3M_CPU0_LVC1_GPIO_2")
	)
	(via
		(at 350.292416 -271.825212)
		(size 0.4572)
		(drill 0.2032)
		(layers "F.Cu" "B.Cu")
		(net "FM_S3M_CPU0_LVC1_GPIO_2")
	)
	(segment
		(start 327.286366 -271.64284)
		(end 316.786514 -271.64284)
		(width 0.12954)
		(layer "B.Cu")
		(net "FM_S3M_CPU0_LVC1_GPIO_2")
	)
	(segment
		(start 289.733228 -263.84504)
		(end 289.733228 -258.28498)
		(width 0.12954)
		(layer "B.Cu")
		(net "FM_S3M_CPU0_LVC1_GPIO_2")
	)
	(segment
		(start 307.191918 -273.35861)
		(end 307.103018 -273.44751)
		(width 0.12954)
		(layer "B.Cu")
		(net "FM_S3M_CPU0_LVC1_GPIO_2")
	)
	(segment
		(start 296.000678 -270.23441)
		(end 295.731438 -269.96517)
		(width 0.12954)
		(layer "B.Cu")
		(net "FM_S3M_CPU0_LVC1_GPIO_2")
	)
	(segment
		(start 291.936678 -266.011914)
		(end 291.267134 -265.34237)
		(width 0.12954)
		(layer "B.Cu")
		(net "FM_S3M_CPU0_LVC1_GPIO_2")
	)
	(segment
		(start 339.212174 -271.50695)
		(end 339.20176 -271.500854)
		(width 0.0889)
		(layer "B.Cu")
		(net "FM_S3M_CPU0_LVC1_GPIO_2")
	)
	(segment
		(start 307.103018 -273.44751)
		(end 305.911758 -273.44751)
		(width 0.12954)
		(layer "B.Cu")
		(net "FM_S3M_CPU0_LVC1_GPIO_2")
	)
	(segment
		(start 334.60055 -271.64284)
		(end 327.286366 -271.64284)
		(width 0.12954)
		(layer "B.Cu")
		(net "FM_S3M_CPU0_LVC1_GPIO_2")
	)
	(segment
		(start 340.156546 -271.50949)
		(end 340.141814 -271.500854)
		(width 0.0889)
		(layer "B.Cu")
		(net "FM_S3M_CPU0_LVC1_GPIO_2")
	)
	(segment
		(start 305.911758 -273.44751)
		(end 304.964338 -272.50009)
		(width 0.12954)
		(layer "B.Cu")
		(net "FM_S3M_CPU0_LVC1_GPIO_2")
	)
	(segment
		(start 291.267134 -265.34237)
		(end 291.230558 -265.34237)
		(width 0.12954)
		(layer "B.Cu")
		(net "FM_S3M_CPU0_LVC1_GPIO_2")
	)
	(segment
		(start 283.684726 -253.789688)
		(end 282.320492 -252.425454)
		(width 0.12954)
		(layer "B.Cu")
		(net "FM_S3M_CPU0_LVC1_GPIO_2")
	)
	(segment
		(start 341.096346 -271.50949)
		(end 341.081614 -271.500854)
		(width 0.0889)
		(layer "B.Cu")
		(net "FM_S3M_CPU0_LVC1_GPIO_2")
	)
	(segment
		(start 310.788304 -273.35861)
		(end 307.191918 -273.35861)
		(width 0.12954)
		(layer "B.Cu")
		(net "FM_S3M_CPU0_LVC1_GPIO_2")
	)
	(segment
		(start 302.040798 -271.32153)
		(end 300.595538 -269.87627)
		(width 0.12954)
		(layer "B.Cu")
		(net "FM_S3M_CPU0_LVC1_GPIO_2")
	)
	(segment
		(start 334.792574 -271.450816)
		(end 334.60055 -271.64284)
		(width 0.0889)
		(layer "B.Cu")
		(net "FM_S3M_CPU0_LVC1_GPIO_2")
	)
	(segment
		(start 281.095958 -195.53809)
		(end 280.237438 -194.67957)
		(width 0.12954)
		(layer "B.Cu")
		(net "FM_S3M_CPU0_LVC1_GPIO_2")
	)
	(segment
		(start 300.595538 -269.87627)
		(end 299.752258 -269.87627)
		(width 0.12954)
		(layer "B.Cu")
		(net "FM_S3M_CPU0_LVC1_GPIO_2")
	)
	(segment
		(start 280.237438 -194.67957)
		(end 279.729438 -194.67957)
		(width 0.12954)
		(layer "B.Cu")
		(net "FM_S3M_CPU0_LVC1_GPIO_2")
	)
	(segment
		(start 299.612558 -270.01597)
		(end 297.984418 -270.01597)
		(width 0.12954)
		(layer "B.Cu")
		(net "FM_S3M_CPU0_LVC1_GPIO_2")
	)
	(segment
		(start 336.392774 -271.50695)
		(end 336.38236 -271.500854)
		(width 0.0889)
		(layer "B.Cu")
		(net "FM_S3M_CPU0_LVC1_GPIO_2")
	)
	(segment
		(start 335.255362 -271.450816)
		(end 334.792574 -271.450816)
		(width 0.0889)
		(layer "B.Cu")
		(net "FM_S3M_CPU0_LVC1_GPIO_2")
	)
	(segment
		(start 289.733228 -258.28498)
		(end 287.418526 -255.970278)
		(width 0.12954)
		(layer "B.Cu")
		(net "FM_S3M_CPU0_LVC1_GPIO_2")
	)
	(segment
		(start 350.292416 -271.825212)
		(end 350.60509 -271.825212)
		(width 0.0889)
		(layer "B.Cu")
		(net "FM_S3M_CPU0_LVC1_GPIO_2")
	)
	(segment
		(start 347.674946 -271.50949)
		(end 347.660214 -271.500854)
		(width 0.0889)
		(layer "B.Cu")
		(net "FM_S3M_CPU0_LVC1_GPIO_2")
	)
	(segment
		(start 350.60509 -271.825212)
		(end 350.662494 -271.767808)
		(width 0.0889)
		(layer "B.Cu")
		(net "FM_S3M_CPU0_LVC1_GPIO_2")
	)
	(segment
		(start 282.320492 -196.366384)
		(end 281.492198 -195.53809)
		(width 0.12954)
		(layer "B.Cu")
		(net "FM_S3M_CPU0_LVC1_GPIO_2")
	)
	(segment
		(start 345.790774 -271.50695)
		(end 345.78036 -271.500854)
		(width 0.0889)
		(layer "B.Cu")
		(net "FM_S3M_CPU0_LVC1_GPIO_2")
	)
	(segment
		(start 295.731438 -269.96517)
		(end 294.669718 -269.96517)
		(width 0.12954)
		(layer "B.Cu")
		(net "FM_S3M_CPU0_LVC1_GPIO_2")
	)
	(segment
		(start 346.735146 -271.50949)
		(end 346.720414 -271.500854)
		(width 0.0889)
		(layer "B.Cu")
		(net "FM_S3M_CPU0_LVC1_GPIO_2")
	)
	(segment
		(start 297.984418 -270.01597)
		(end 297.765978 -270.23441)
		(width 0.12954)
		(layer "B.Cu")
		(net "FM_S3M_CPU0_LVC1_GPIO_2")
	)
	(segment
		(start 291.936678 -267.23213)
		(end 291.936678 -266.011914)
		(width 0.12954)
		(layer "B.Cu")
		(net "FM_S3M_CPU0_LVC1_GPIO_2")
	)
	(segment
		(start 342.975946 -271.50949)
		(end 342.961214 -271.500854)
		(width 0.0889)
		(layer "B.Cu")
		(net "FM_S3M_CPU0_LVC1_GPIO_2")
	)
	(segment
		(start 287.418526 -255.970278)
		(end 287.03524 -255.970278)
		(width 0.12954)
		(layer "B.Cu")
		(net "FM_S3M_CPU0_LVC1_GPIO_2")
	)
	(segment
		(start 337.332828 -271.50695)
		(end 337.322414 -271.500854)
		(width 0.0889)
		(layer "B.Cu")
		(net "FM_S3M_CPU0_LVC1_GPIO_2")
	)
	(segment
		(start 311.121044 -273.69135)
		(end 310.788304 -273.35861)
		(width 0.12954)
		(layer "B.Cu")
		(net "FM_S3M_CPU0_LVC1_GPIO_2")
	)
	(segment
		(start 303.750218 -272.50009)
		(end 302.571658 -271.32153)
		(width 0.12954)
		(layer "B.Cu")
		(net "FM_S3M_CPU0_LVC1_GPIO_2")
	)
	(segment
		(start 291.230558 -265.34237)
		(end 289.733228 -263.84504)
		(width 0.12954)
		(layer "B.Cu")
		(net "FM_S3M_CPU0_LVC1_GPIO_2")
	)
	(segment
		(start 343.915746 -271.50949)
		(end 343.901014 -271.500854)
		(width 0.0889)
		(layer "B.Cu")
		(net "FM_S3M_CPU0_LVC1_GPIO_2")
	)
	(segment
		(start 284.85465 -253.789688)
		(end 283.684726 -253.789688)
		(width 0.12954)
		(layer "B.Cu")
		(net "FM_S3M_CPU0_LVC1_GPIO_2")
	)
	(segment
		(start 314.738004 -273.69135)
		(end 311.121044 -273.69135)
		(width 0.12954)
		(layer "B.Cu")
		(net "FM_S3M_CPU0_LVC1_GPIO_2")
	)
	(segment
		(start 302.571658 -271.32153)
		(end 302.040798 -271.32153)
		(width 0.12954)
		(layer "B.Cu")
		(net "FM_S3M_CPU0_LVC1_GPIO_2")
	)
	(segment
		(start 316.786514 -271.64284)
		(end 314.738004 -273.69135)
		(width 0.12954)
		(layer "B.Cu")
		(net "FM_S3M_CPU0_LVC1_GPIO_2")
	)
	(segment
		(start 299.752258 -269.87627)
		(end 299.612558 -270.01597)
		(width 0.12954)
		(layer "B.Cu")
		(net "FM_S3M_CPU0_LVC1_GPIO_2")
	)
	(segment
		(start 279.119584 -194.069716)
		(end 278.128984 -194.069716)
		(width 0.12954)
		(layer "B.Cu")
		(net "FM_S3M_CPU0_LVC1_GPIO_2")
	)
	(segment
		(start 297.765978 -270.23441)
		(end 296.000678 -270.23441)
		(width 0.12954)
		(layer "B.Cu")
		(net "FM_S3M_CPU0_LVC1_GPIO_2")
	)
	(segment
		(start 279.729438 -194.67957)
		(end 279.119584 -194.069716)
		(width 0.12954)
		(layer "B.Cu")
		(net "FM_S3M_CPU0_LVC1_GPIO_2")
	)
	(segment
		(start 344.851228 -271.50695)
		(end 344.840814 -271.500854)
		(width 0.0889)
		(layer "B.Cu")
		(net "FM_S3M_CPU0_LVC1_GPIO_2")
	)
	(segment
		(start 294.669718 -269.96517)
		(end 291.936678 -267.23213)
		(width 0.12954)
		(layer "B.Cu")
		(net "FM_S3M_CPU0_LVC1_GPIO_2")
	)
	(segment
		(start 281.492198 -195.53809)
		(end 281.095958 -195.53809)
		(width 0.12954)
		(layer "B.Cu")
		(net "FM_S3M_CPU0_LVC1_GPIO_2")
	)
	(segment
		(start 287.03524 -255.970278)
		(end 284.85465 -253.789688)
		(width 0.12954)
		(layer "B.Cu")
		(net "FM_S3M_CPU0_LVC1_GPIO_2")
	)
	(segment
		(start 282.320492 -252.425454)
		(end 282.320492 -196.366384)
		(width 0.12954)
		(layer "B.Cu")
		(net "FM_S3M_CPU0_LVC1_GPIO_2")
	)
	(segment
		(start 304.964338 -272.50009)
		(end 303.750218 -272.50009)
		(width 0.12954)
		(layer "B.Cu")
		(net "FM_S3M_CPU0_LVC1_GPIO_2")
	)
	(arc
		(start 340.707218 -271.500854)
		(mid 340.433019 -271.576689)
		(end 340.156546 -271.50949)
		(width 0.0889)
		(layer "B.Cu")
		(net "FM_S3M_CPU0_LVC1_GPIO_2")
	)
	(arc
		(start 342.586818 -271.500854)
		(mid 342.304116 -271.57663)
		(end 342.021414 -271.500854)
		(width 0.0889)
		(layer "B.Cu")
		(net "FM_S3M_CPU0_LVC1_GPIO_2")
	)
	(arc
		(start 344.466418 -271.500854)
		(mid 344.192219 -271.576689)
		(end 343.915746 -271.50949)
		(width 0.0889)
		(layer "B.Cu")
		(net "FM_S3M_CPU0_LVC1_GPIO_2")
	)
	(arc
		(start 335.44256 -271.500854)
		(mid 335.352253 -271.463525)
		(end 335.255362 -271.450816)
		(width 0.0889)
		(layer "B.Cu")
		(net "FM_S3M_CPU0_LVC1_GPIO_2")
	)
	(arc
		(start 345.405964 -271.500854)
		(mid 345.129405 -271.576597)
		(end 344.851228 -271.50695)
		(width 0.0889)
		(layer "B.Cu")
		(net "FM_S3M_CPU0_LVC1_GPIO_2")
	)
	(arc
		(start 348.600014 -271.500854)
		(mid 348.412816 -271.450711)
		(end 348.225618 -271.500854)
		(width 0.0889)
		(layer "B.Cu")
		(net "FM_S3M_CPU0_LVC1_GPIO_2")
	)
	(arc
		(start 348.225618 -271.500854)
		(mid 347.951419 -271.576689)
		(end 347.674946 -271.50949)
		(width 0.0889)
		(layer "B.Cu")
		(net "FM_S3M_CPU0_LVC1_GPIO_2")
	)
	(arc
		(start 347.285818 -271.500854)
		(mid 347.011619 -271.576689)
		(end 346.735146 -271.50949)
		(width 0.0889)
		(layer "B.Cu")
		(net "FM_S3M_CPU0_LVC1_GPIO_2")
	)
	(arc
		(start 349.539814 -271.500854)
		(mid 349.352616 -271.450711)
		(end 349.165418 -271.500854)
		(width 0.0889)
		(layer "B.Cu")
		(net "FM_S3M_CPU0_LVC1_GPIO_2")
	)
	(arc
		(start 342.961214 -271.500854)
		(mid 342.774016 -271.450711)
		(end 342.586818 -271.500854)
		(width 0.0889)
		(layer "B.Cu")
		(net "FM_S3M_CPU0_LVC1_GPIO_2")
	)
	(arc
		(start 343.526618 -271.500854)
		(mid 343.252419 -271.576689)
		(end 342.975946 -271.50949)
		(width 0.0889)
		(layer "B.Cu")
		(net "FM_S3M_CPU0_LVC1_GPIO_2")
	)
	(arc
		(start 336.38236 -271.500854)
		(mid 336.195162 -271.450711)
		(end 336.007964 -271.500854)
		(width 0.0889)
		(layer "B.Cu")
		(net "FM_S3M_CPU0_LVC1_GPIO_2")
	)
	(arc
		(start 349.165418 -271.500854)
		(mid 348.882716 -271.57663)
		(end 348.600014 -271.500854)
		(width 0.0889)
		(layer "B.Cu")
		(net "FM_S3M_CPU0_LVC1_GPIO_2")
	)
	(arc
		(start 336.007964 -271.500854)
		(mid 335.725262 -271.57663)
		(end 335.44256 -271.500854)
		(width 0.0889)
		(layer "B.Cu")
		(net "FM_S3M_CPU0_LVC1_GPIO_2")
	)
	(arc
		(start 341.081614 -271.500854)
		(mid 340.894416 -271.450711)
		(end 340.707218 -271.500854)
		(width 0.0889)
		(layer "B.Cu")
		(net "FM_S3M_CPU0_LVC1_GPIO_2")
	)
	(arc
		(start 342.021414 -271.500854)
		(mid 341.834216 -271.450711)
		(end 341.647018 -271.500854)
		(width 0.0889)
		(layer "B.Cu")
		(net "FM_S3M_CPU0_LVC1_GPIO_2")
	)
	(arc
		(start 339.767418 -271.500854)
		(mid 339.490605 -271.576724)
		(end 339.212174 -271.50695)
		(width 0.0889)
		(layer "B.Cu")
		(net "FM_S3M_CPU0_LVC1_GPIO_2")
	)
	(arc
		(start 338.827364 -271.500854)
		(mid 338.544662 -271.57663)
		(end 338.26196 -271.500854)
		(width 0.0889)
		(layer "B.Cu")
		(net "FM_S3M_CPU0_LVC1_GPIO_2")
	)
	(arc
		(start 346.720414 -271.500854)
		(mid 346.533216 -271.450711)
		(end 346.346018 -271.500854)
		(width 0.0889)
		(layer "B.Cu")
		(net "FM_S3M_CPU0_LVC1_GPIO_2")
	)
	(arc
		(start 343.901014 -271.500854)
		(mid 343.713816 -271.450711)
		(end 343.526618 -271.500854)
		(width 0.0889)
		(layer "B.Cu")
		(net "FM_S3M_CPU0_LVC1_GPIO_2")
	)
	(arc
		(start 350.105218 -271.500854)
		(mid 349.822516 -271.57663)
		(end 349.539814 -271.500854)
		(width 0.0889)
		(layer "B.Cu")
		(net "FM_S3M_CPU0_LVC1_GPIO_2")
	)
	(arc
		(start 346.346018 -271.500854)
		(mid 346.069205 -271.576724)
		(end 345.790774 -271.50695)
		(width 0.0889)
		(layer "B.Cu")
		(net "FM_S3M_CPU0_LVC1_GPIO_2")
	)
	(arc
		(start 337.887564 -271.500854)
		(mid 337.611005 -271.576597)
		(end 337.332828 -271.50695)
		(width 0.0889)
		(layer "B.Cu")
		(net "FM_S3M_CPU0_LVC1_GPIO_2")
	)
	(arc
		(start 344.840814 -271.500854)
		(mid 344.653616 -271.450711)
		(end 344.466418 -271.500854)
		(width 0.0889)
		(layer "B.Cu")
		(net "FM_S3M_CPU0_LVC1_GPIO_2")
	)
	(arc
		(start 337.322414 -271.500854)
		(mid 337.135216 -271.450711)
		(end 336.948018 -271.500854)
		(width 0.0889)
		(layer "B.Cu")
		(net "FM_S3M_CPU0_LVC1_GPIO_2")
	)
	(arc
		(start 350.662494 -271.767808)
		(mid 350.454211 -271.487462)
		(end 350.105218 -271.500854)
		(width 0.0889)
		(layer "B.Cu")
		(net "FM_S3M_CPU0_LVC1_GPIO_2")
	)
	(arc
		(start 339.20176 -271.500854)
		(mid 339.014562 -271.450711)
		(end 338.827364 -271.500854)
		(width 0.0889)
		(layer "B.Cu")
		(net "FM_S3M_CPU0_LVC1_GPIO_2")
	)
	(arc
		(start 347.660214 -271.500854)
		(mid 347.473016 -271.450711)
		(end 347.285818 -271.500854)
		(width 0.0889)
		(layer "B.Cu")
		(net "FM_S3M_CPU0_LVC1_GPIO_2")
	)
	(arc
		(start 336.948018 -271.500854)
		(mid 336.671205 -271.576724)
		(end 336.392774 -271.50695)
		(width 0.0889)
		(layer "B.Cu")
		(net "FM_S3M_CPU0_LVC1_GPIO_2")
	)
	(arc
		(start 341.647018 -271.500854)
		(mid 341.372819 -271.576689)
		(end 341.096346 -271.50949)
		(width 0.0889)
		(layer "B.Cu")
		(net "FM_S3M_CPU0_LVC1_GPIO_2")
	)
	(arc
		(start 345.78036 -271.500854)
		(mid 345.593162 -271.450711)
		(end 345.405964 -271.500854)
		(width 0.0889)
		(layer "B.Cu")
		(net "FM_S3M_CPU0_LVC1_GPIO_2")
	)
	(arc
		(start 340.141814 -271.500854)
		(mid 339.954616 -271.450711)
		(end 339.767418 -271.500854)
		(width 0.0889)
		(layer "B.Cu")
		(net "FM_S3M_CPU0_LVC1_GPIO_2")
	)
	(arc
		(start 338.26196 -271.500854)
		(mid 338.074762 -271.450711)
		(end 337.887564 -271.500854)
		(width 0.0889)
		(layer "B.Cu")
		(net "FM_S3M_CPU0_LVC1_GPIO_2")
	)
	(segment
		(start 350.292162 -273.452844)
		(end 350.292416 -273.453098)
		(width 0.12954)
		(layer "F.Cu")
		(net "FM_S3M_CPU0_LVC1_GPIO_1")
	)
	(segment
		(start 350.292162 -272.917158)
		(end 350.292162 -273.452844)
		(width 0.12954)
		(layer "F.Cu")
		(net "FM_S3M_CPU0_LVC1_GPIO_1")
	)
	(via
		(at 275.431504 -196.787516)
		(size 0.6604)
		(drill 0.3302)
		(layers "F.Cu" "B.Cu")
		(net "FM_S3M_CPU0_LVC1_GPIO_1")
	)
	(via
		(at 350.292416 -273.453098)
		(size 0.4572)
		(drill 0.2032)
		(layers "F.Cu" "B.Cu")
		(net "FM_S3M_CPU0_LVC1_GPIO_1")
	)
	(via
		(at 321.509136 -273.520662)
		(size 0.6604)
		(drill 0.3302)
		(layers "F.Cu" "B.Cu")
		(net "FM_S3M_CPU0_LVC1_GPIO_1")
	)
	(segment
		(start 275.431504 -196.787516)
		(end 274.994878 -196.35089)
		(width 0.12954)
		(layer "B.Cu")
		(net "FM_S3M_CPU0_LVC1_GPIO_1")
	)
	(segment
		(start 340.156546 -273.137376)
		(end 340.141814 -273.12874)
		(width 0.0889)
		(layer "B.Cu")
		(net "FM_S3M_CPU0_LVC1_GPIO_1")
	)
	(segment
		(start 303.064164 -274.26539)
		(end 302.096424 -274.26539)
		(width 0.12954)
		(layer "B.Cu")
		(net "FM_S3M_CPU0_LVC1_GPIO_1")
	)
	(segment
		(start 335.731358 -272.953226)
		(end 335.433162 -272.953226)
		(width 0.12954)
		(layer "B.Cu")
		(net "FM_S3M_CPU0_LVC1_GPIO_1")
	)
	(segment
		(start 343.915746 -273.137376)
		(end 343.901014 -273.12874)
		(width 0.0889)
		(layer "B.Cu")
		(net "FM_S3M_CPU0_LVC1_GPIO_1")
	)
	(segment
		(start 348.610428 -273.134836)
		(end 348.600014 -273.12874)
		(width 0.0889)
		(layer "B.Cu")
		(net "FM_S3M_CPU0_LVC1_GPIO_1")
	)
	(segment
		(start 349.922084 -273.352768)
		(end 349.53956 -273.12874)
		(width 0.0889)
		(layer "B.Cu")
		(net "FM_S3M_CPU0_LVC1_GPIO_1")
	)
	(segment
		(start 288.698178 -266.01039)
		(end 287.872678 -265.18489)
		(width 0.12954)
		(layer "B.Cu")
		(net "FM_S3M_CPU0_LVC1_GPIO_1")
	)
	(segment
		(start 295.457118 -272.57121)
		(end 293.841678 -272.57121)
		(width 0.12954)
		(layer "B.Cu")
		(net "FM_S3M_CPU0_LVC1_GPIO_1")
	)
	(segment
		(start 292.040818 -272.64233)
		(end 290.003738 -270.60525)
		(width 0.12954)
		(layer "B.Cu")
		(net "FM_S3M_CPU0_LVC1_GPIO_1")
	)
	(segment
		(start 342.031828 -273.134836)
		(end 342.021414 -273.12874)
		(width 0.0889)
		(layer "B.Cu")
		(net "FM_S3M_CPU0_LVC1_GPIO_1")
	)
	(segment
		(start 293.770558 -272.64233)
		(end 292.040818 -272.64233)
		(width 0.12954)
		(layer "B.Cu")
		(net "FM_S3M_CPU0_LVC1_GPIO_1")
	)
	(segment
		(start 311.507378 -275.20773)
		(end 306.927758 -275.20773)
		(width 0.12954)
		(layer "B.Cu")
		(net "FM_S3M_CPU0_LVC1_GPIO_1")
	)
	(segment
		(start 295.604438 -272.42389)
		(end 295.457118 -272.57121)
		(width 0.12954)
		(layer "B.Cu")
		(net "FM_S3M_CPU0_LVC1_GPIO_1")
	)
	(segment
		(start 279.75306 -255.228852)
		(end 278.723598 -254.19939)
		(width 0.12954)
		(layer "B.Cu")
		(net "FM_S3M_CPU0_LVC1_GPIO_1")
	)
	(segment
		(start 339.216746 -273.137376)
		(end 339.202014 -273.12874)
		(width 0.0889)
		(layer "B.Cu")
		(net "FM_S3M_CPU0_LVC1_GPIO_1")
	)
	(segment
		(start 290.003738 -270.60525)
		(end 290.003738 -267.93317)
		(width 0.12954)
		(layer "B.Cu")
		(net "FM_S3M_CPU0_LVC1_GPIO_1")
	)
	(segment
		(start 306.927758 -275.20773)
		(end 306.699158 -274.97913)
		(width 0.12954)
		(layer "B.Cu")
		(net "FM_S3M_CPU0_LVC1_GPIO_1")
	)
	(segment
		(start 293.841678 -272.57121)
		(end 293.770558 -272.64233)
		(width 0.12954)
		(layer "B.Cu")
		(net "FM_S3M_CPU0_LVC1_GPIO_1")
	)
	(segment
		(start 278.723598 -254.19939)
		(end 278.723598 -199.40905)
		(width 0.12954)
		(layer "B.Cu")
		(net "FM_S3M_CPU0_LVC1_GPIO_1")
	)
	(segment
		(start 299.490638 -272.63217)
		(end 299.376338 -272.51787)
		(width 0.12954)
		(layer "B.Cu")
		(net "FM_S3M_CPU0_LVC1_GPIO_1")
	)
	(segment
		(start 311.735978 -274.97913)
		(end 311.507378 -275.20773)
		(width 0.12954)
		(layer "B.Cu")
		(net "FM_S3M_CPU0_LVC1_GPIO_1")
	)
	(segment
		(start 303.777904 -274.97913)
		(end 303.064164 -274.26539)
		(width 0.12954)
		(layer "B.Cu")
		(net "FM_S3M_CPU0_LVC1_GPIO_1")
	)
	(segment
		(start 302.096424 -274.26539)
		(end 300.463204 -272.63217)
		(width 0.12954)
		(layer "B.Cu")
		(net "FM_S3M_CPU0_LVC1_GPIO_1")
	)
	(segment
		(start 299.376338 -272.51787)
		(end 298.522898 -272.51787)
		(width 0.12954)
		(layer "B.Cu")
		(net "FM_S3M_CPU0_LVC1_GPIO_1")
	)
	(segment
		(start 346.735146 -273.137376)
		(end 346.720414 -273.12874)
		(width 0.0889)
		(layer "B.Cu")
		(net "FM_S3M_CPU0_LVC1_GPIO_1")
	)
	(segment
		(start 275.891498 -197.24751)
		(end 275.431504 -196.787516)
		(width 0.12954)
		(layer "B.Cu")
		(net "FM_S3M_CPU0_LVC1_GPIO_1")
	)
	(segment
		(start 298.428918 -272.42389)
		(end 295.604438 -272.42389)
		(width 0.12954)
		(layer "B.Cu")
		(net "FM_S3M_CPU0_LVC1_GPIO_1")
	)
	(segment
		(start 298.522898 -272.51787)
		(end 298.428918 -272.42389)
		(width 0.12954)
		(layer "B.Cu")
		(net "FM_S3M_CPU0_LVC1_GPIO_1")
	)
	(segment
		(start 332.198218 -272.963386)
		(end 331.640942 -273.520662)
		(width 0.12954)
		(layer "B.Cu")
		(net "FM_S3M_CPU0_LVC1_GPIO_1")
	)
	(segment
		(start 338.827618 -273.12874)
		(end 338.817204 -273.134836)
		(width 0.0889)
		(layer "B.Cu")
		(net "FM_S3M_CPU0_LVC1_GPIO_1")
	)
	(segment
		(start 347.674946 -273.137376)
		(end 347.660214 -273.12874)
		(width 0.0889)
		(layer "B.Cu")
		(net "FM_S3M_CPU0_LVC1_GPIO_1")
	)
	(segment
		(start 287.872678 -265.18489)
		(end 287.872678 -258.11607)
		(width 0.12954)
		(layer "B.Cu")
		(net "FM_S3M_CPU0_LVC1_GPIO_1")
	)
	(segment
		(start 321.509136 -273.520662)
		(end 317.060326 -273.520662)
		(width 0.12954)
		(layer "B.Cu")
		(net "FM_S3M_CPU0_LVC1_GPIO_1")
	)
	(segment
		(start 290.003738 -267.93317)
		(end 288.698178 -266.62761)
		(width 0.12954)
		(layer "B.Cu")
		(net "FM_S3M_CPU0_LVC1_GPIO_1")
	)
	(segment
		(start 331.640942 -273.520662)
		(end 321.509136 -273.520662)
		(width 0.12954)
		(layer "B.Cu")
		(net "FM_S3M_CPU0_LVC1_GPIO_1")
	)
	(segment
		(start 335.433162 -272.953226)
		(end 335.423002 -272.963386)
		(width 0.12954)
		(layer "B.Cu")
		(net "FM_S3M_CPU0_LVC1_GPIO_1")
	)
	(segment
		(start 341.096346 -273.137376)
		(end 341.081614 -273.12874)
		(width 0.0889)
		(layer "B.Cu")
		(net "FM_S3M_CPU0_LVC1_GPIO_1")
	)
	(segment
		(start 345.795346 -273.137376)
		(end 345.780614 -273.12874)
		(width 0.0889)
		(layer "B.Cu")
		(net "FM_S3M_CPU0_LVC1_GPIO_1")
	)
	(segment
		(start 274.994878 -196.35089)
		(end 274.994878 -194.232022)
		(width 0.12954)
		(layer "B.Cu")
		(net "FM_S3M_CPU0_LVC1_GPIO_1")
	)
	(segment
		(start 306.699158 -274.97913)
		(end 303.777904 -274.97913)
		(width 0.12954)
		(layer "B.Cu")
		(net "FM_S3M_CPU0_LVC1_GPIO_1")
	)
	(segment
		(start 335.423002 -272.963386)
		(end 332.198218 -272.963386)
		(width 0.12954)
		(layer "B.Cu")
		(net "FM_S3M_CPU0_LVC1_GPIO_1")
	)
	(segment
		(start 274.994878 -194.232022)
		(end 275.157184 -194.069716)
		(width 0.12954)
		(layer "B.Cu")
		(net "FM_S3M_CPU0_LVC1_GPIO_1")
	)
	(segment
		(start 317.060326 -273.520662)
		(end 315.601858 -274.97913)
		(width 0.12954)
		(layer "B.Cu")
		(net "FM_S3M_CPU0_LVC1_GPIO_1")
	)
	(segment
		(start 287.872678 -258.11607)
		(end 284.98546 -255.228852)
		(width 0.12954)
		(layer "B.Cu")
		(net "FM_S3M_CPU0_LVC1_GPIO_1")
	)
	(segment
		(start 336.947764 -273.12874)
		(end 336.933032 -273.137376)
		(width 0.0889)
		(layer "B.Cu")
		(net "FM_S3M_CPU0_LVC1_GPIO_1")
	)
	(segment
		(start 284.98546 -255.228852)
		(end 279.75306 -255.228852)
		(width 0.12954)
		(layer "B.Cu")
		(net "FM_S3M_CPU0_LVC1_GPIO_1")
	)
	(segment
		(start 342.971374 -273.134836)
		(end 342.96096 -273.12874)
		(width 0.0889)
		(layer "B.Cu")
		(net "FM_S3M_CPU0_LVC1_GPIO_1")
	)
	(segment
		(start 300.463204 -272.63217)
		(end 299.490638 -272.63217)
		(width 0.12954)
		(layer "B.Cu")
		(net "FM_S3M_CPU0_LVC1_GPIO_1")
	)
	(segment
		(start 288.698178 -266.62761)
		(end 288.698178 -266.01039)
		(width 0.12954)
		(layer "B.Cu")
		(net "FM_S3M_CPU0_LVC1_GPIO_1")
	)
	(segment
		(start 315.601858 -274.97913)
		(end 311.735978 -274.97913)
		(width 0.12954)
		(layer "B.Cu")
		(net "FM_S3M_CPU0_LVC1_GPIO_1")
	)
	(segment
		(start 278.723598 -199.40905)
		(end 276.562058 -197.24751)
		(width 0.12954)
		(layer "B.Cu")
		(net "FM_S3M_CPU0_LVC1_GPIO_1")
	)
	(segment
		(start 276.562058 -197.24751)
		(end 275.891498 -197.24751)
		(width 0.12954)
		(layer "B.Cu")
		(net "FM_S3M_CPU0_LVC1_GPIO_1")
	)
	(arc
		(start 338.817204 -273.134836)
		(mid 338.538772 -273.204682)
		(end 338.26196 -273.12874)
		(width 0.0889)
		(layer "B.Cu")
		(net "FM_S3M_CPU0_LVC1_GPIO_1")
	)
	(arc
		(start 339.202014 -273.12874)
		(mid 339.014816 -273.078597)
		(end 338.827618 -273.12874)
		(width 0.0889)
		(layer "B.Cu")
		(net "FM_S3M_CPU0_LVC1_GPIO_1")
	)
	(arc
		(start 339.767418 -273.12874)
		(mid 339.493219 -273.204575)
		(end 339.216746 -273.137376)
		(width 0.0889)
		(layer "B.Cu")
		(net "FM_S3M_CPU0_LVC1_GPIO_1")
	)
	(arc
		(start 348.225618 -273.12874)
		(mid 347.951419 -273.204575)
		(end 347.674946 -273.137376)
		(width 0.0889)
		(layer "B.Cu")
		(net "FM_S3M_CPU0_LVC1_GPIO_1")
	)
	(arc
		(start 341.081614 -273.12874)
		(mid 340.894416 -273.078597)
		(end 340.707218 -273.12874)
		(width 0.0889)
		(layer "B.Cu")
		(net "FM_S3M_CPU0_LVC1_GPIO_1")
	)
	(arc
		(start 340.141814 -273.12874)
		(mid 339.954616 -273.078597)
		(end 339.767418 -273.12874)
		(width 0.0889)
		(layer "B.Cu")
		(net "FM_S3M_CPU0_LVC1_GPIO_1")
	)
	(arc
		(start 336.933032 -273.137376)
		(mid 336.656557 -273.204696)
		(end 336.38236 -273.12874)
		(width 0.0889)
		(layer "B.Cu")
		(net "FM_S3M_CPU0_LVC1_GPIO_1")
	)
	(arc
		(start 350.292416 -273.453098)
		(mid 350.10056 -273.427615)
		(end 349.922084 -273.352768)
		(width 0.0889)
		(layer "B.Cu")
		(net "FM_S3M_CPU0_LVC1_GPIO_1")
	)
	(arc
		(start 348.600014 -273.12874)
		(mid 348.412816 -273.078597)
		(end 348.225618 -273.12874)
		(width 0.0889)
		(layer "B.Cu")
		(net "FM_S3M_CPU0_LVC1_GPIO_1")
	)
	(arc
		(start 345.406218 -273.12874)
		(mid 345.123516 -273.204516)
		(end 344.840814 -273.12874)
		(width 0.0889)
		(layer "B.Cu")
		(net "FM_S3M_CPU0_LVC1_GPIO_1")
	)
	(arc
		(start 342.96096 -273.12874)
		(mid 342.773762 -273.078597)
		(end 342.586564 -273.12874)
		(width 0.0889)
		(layer "B.Cu")
		(net "FM_S3M_CPU0_LVC1_GPIO_1")
	)
	(arc
		(start 341.647018 -273.12874)
		(mid 341.372819 -273.204575)
		(end 341.096346 -273.137376)
		(width 0.0889)
		(layer "B.Cu")
		(net "FM_S3M_CPU0_LVC1_GPIO_1")
	)
	(arc
		(start 344.840814 -273.12874)
		(mid 344.653616 -273.078597)
		(end 344.466418 -273.12874)
		(width 0.0889)
		(layer "B.Cu")
		(net "FM_S3M_CPU0_LVC1_GPIO_1")
	)
	(arc
		(start 343.901014 -273.12874)
		(mid 343.713816 -273.078597)
		(end 343.526618 -273.12874)
		(width 0.0889)
		(layer "B.Cu")
		(net "FM_S3M_CPU0_LVC1_GPIO_1")
	)
	(arc
		(start 340.707218 -273.12874)
		(mid 340.433019 -273.204575)
		(end 340.156546 -273.137376)
		(width 0.0889)
		(layer "B.Cu")
		(net "FM_S3M_CPU0_LVC1_GPIO_1")
	)
	(arc
		(start 347.285818 -273.12874)
		(mid 347.011619 -273.204575)
		(end 346.735146 -273.137376)
		(width 0.0889)
		(layer "B.Cu")
		(net "FM_S3M_CPU0_LVC1_GPIO_1")
	)
	(arc
		(start 342.586564 -273.12874)
		(mid 342.310005 -273.204483)
		(end 342.031828 -273.134836)
		(width 0.0889)
		(layer "B.Cu")
		(net "FM_S3M_CPU0_LVC1_GPIO_1")
	)
	(arc
		(start 346.346018 -273.12874)
		(mid 346.071819 -273.204575)
		(end 345.795346 -273.137376)
		(width 0.0889)
		(layer "B.Cu")
		(net "FM_S3M_CPU0_LVC1_GPIO_1")
	)
	(arc
		(start 344.466418 -273.12874)
		(mid 344.192219 -273.204575)
		(end 343.915746 -273.137376)
		(width 0.0889)
		(layer "B.Cu")
		(net "FM_S3M_CPU0_LVC1_GPIO_1")
	)
	(arc
		(start 338.26196 -273.12874)
		(mid 338.074762 -273.078597)
		(end 337.887564 -273.12874)
		(width 0.0889)
		(layer "B.Cu")
		(net "FM_S3M_CPU0_LVC1_GPIO_1")
	)
	(arc
		(start 343.526618 -273.12874)
		(mid 343.249805 -273.20461)
		(end 342.971374 -273.134836)
		(width 0.0889)
		(layer "B.Cu")
		(net "FM_S3M_CPU0_LVC1_GPIO_1")
	)
	(arc
		(start 345.780614 -273.12874)
		(mid 345.593416 -273.078597)
		(end 345.406218 -273.12874)
		(width 0.0889)
		(layer "B.Cu")
		(net "FM_S3M_CPU0_LVC1_GPIO_1")
	)
	(arc
		(start 346.720414 -273.12874)
		(mid 346.533216 -273.078597)
		(end 346.346018 -273.12874)
		(width 0.0889)
		(layer "B.Cu")
		(net "FM_S3M_CPU0_LVC1_GPIO_1")
	)
	(arc
		(start 349.53956 -273.12874)
		(mid 349.352362 -273.078597)
		(end 349.165164 -273.12874)
		(width 0.0889)
		(layer "B.Cu")
		(net "FM_S3M_CPU0_LVC1_GPIO_1")
	)
	(arc
		(start 349.165164 -273.12874)
		(mid 348.888605 -273.204483)
		(end 348.610428 -273.134836)
		(width 0.0889)
		(layer "B.Cu")
		(net "FM_S3M_CPU0_LVC1_GPIO_1")
	)
	(arc
		(start 342.021414 -273.12874)
		(mid 341.834216 -273.078597)
		(end 341.647018 -273.12874)
		(width 0.0889)
		(layer "B.Cu")
		(net "FM_S3M_CPU0_LVC1_GPIO_1")
	)
	(arc
		(start 347.660214 -273.12874)
		(mid 347.473016 -273.078597)
		(end 347.285818 -273.12874)
		(width 0.0889)
		(layer "B.Cu")
		(net "FM_S3M_CPU0_LVC1_GPIO_1")
	)
	(arc
		(start 336.38236 -273.12874)
		(mid 336.068485 -272.997856)
		(end 335.731358 -272.953226)
		(width 0.0889)
		(layer "B.Cu")
		(net "FM_S3M_CPU0_LVC1_GPIO_1")
	)
	(arc
		(start 337.887564 -273.12874)
		(mid 337.604862 -273.204516)
		(end 337.32216 -273.12874)
		(width 0.0889)
		(layer "B.Cu")
		(net "FM_S3M_CPU0_LVC1_GPIO_1")
	)
	(arc
		(start 337.32216 -273.12874)
		(mid 337.134962 -273.078597)
		(end 336.947764 -273.12874)
		(width 0.0889)
		(layer "B.Cu")
		(net "FM_S3M_CPU0_LVC1_GPIO_1")
	)
	(segment
		(start 351.701862 -272.103596)
		(end 351.701862 -272.639282)
		(width 0.12954)
		(layer "F.Cu")
		(net "FM_S3M_CPU0_LVC1_GPIO_0")
	)
	(segment
		(start 351.702116 -272.103342)
		(end 351.701862 -272.103596)
		(width 0.12954)
		(layer "F.Cu")
		(net "FM_S3M_CPU0_LVC1_GPIO_0")
	)
	(via
		(at 318.481202 -272.228056)
		(size 0.6604)
		(drill 0.3302)
		(layers "F.Cu" "B.Cu")
		(net "FM_S3M_CPU0_LVC1_GPIO_0")
	)
	(via
		(at 351.701862 -272.639282)
		(size 0.4572)
		(drill 0.2032)
		(layers "F.Cu" "B.Cu")
		(net "FM_S3M_CPU0_LVC1_GPIO_0")
	)
	(segment
		(start 345.790774 -272.143474)
		(end 345.78036 -272.14957)
		(width 0.0889)
		(layer "B.Cu")
		(net "FM_S3M_CPU0_LVC1_GPIO_0")
	)
	(segment
		(start 306.836572 -273.94535)
		(end 304.283618 -273.94535)
		(width 0.12954)
		(layer "B.Cu")
		(net "FM_S3M_CPU0_LVC1_GPIO_0")
	)
	(segment
		(start 318.470026 -272.228056)
		(end 318.470026 -272.22831)
		(width 0.12954)
		(layer "B.Cu")
		(net "FM_S3M_CPU0_LVC1_GPIO_0")
	)
	(segment
		(start 295.969944 -270.67383)
		(end 295.776904 -270.86687)
		(width 0.12954)
		(layer "B.Cu")
		(net "FM_S3M_CPU0_LVC1_GPIO_0")
	)
	(segment
		(start 290.808918 -266.16787)
		(end 289.643058 -265.00201)
		(width 0.12954)
		(layer "B.Cu")
		(net "FM_S3M_CPU0_LVC1_GPIO_0")
	)
	(segment
		(start 304.283618 -273.94535)
		(end 303.016158 -272.67789)
		(width 0.12954)
		(layer "B.Cu")
		(net "FM_S3M_CPU0_LVC1_GPIO_0")
	)
	(segment
		(start 341.096346 -272.140934)
		(end 341.081614 -272.14957)
		(width 0.0889)
		(layer "B.Cu")
		(net "FM_S3M_CPU0_LVC1_GPIO_0")
	)
	(segment
		(start 349.554546 -272.140934)
		(end 349.539814 -272.14957)
		(width 0.0889)
		(layer "B.Cu")
		(net "FM_S3M_CPU0_LVC1_GPIO_0")
	)
	(segment
		(start 318.481202 -272.228056)
		(end 318.470026 -272.228056)
		(width 0.12954)
		(layer "B.Cu")
		(net "FM_S3M_CPU0_LVC1_GPIO_0")
	)
	(segment
		(start 351.701862 -272.639282)
		(end 351.389188 -272.639282)
		(width 0.0889)
		(layer "B.Cu")
		(net "FM_S3M_CPU0_LVC1_GPIO_0")
	)
	(segment
		(start 318.470026 -272.22831)
		(end 316.874398 -272.22831)
		(width 0.12954)
		(layer "B.Cu")
		(net "FM_S3M_CPU0_LVC1_GPIO_0")
	)
	(segment
		(start 297.796204 -270.67383)
		(end 295.969944 -270.67383)
		(width 0.12954)
		(layer "B.Cu")
		(net "FM_S3M_CPU0_LVC1_GPIO_0")
	)
	(segment
		(start 290.808918 -268.00429)
		(end 290.808918 -266.16787)
		(width 0.12954)
		(layer "B.Cu")
		(net "FM_S3M_CPU0_LVC1_GPIO_0")
	)
	(segment
		(start 283.616146 -254.119888)
		(end 281.217878 -251.72162)
		(width 0.12954)
		(layer "B.Cu")
		(net "FM_S3M_CPU0_LVC1_GPIO_0")
	)
	(segment
		(start 280.153618 -195.05549)
		(end 279.109678 -195.05549)
		(width 0.12954)
		(layer "B.Cu")
		(net "FM_S3M_CPU0_LVC1_GPIO_0")
	)
	(segment
		(start 279.109678 -195.05549)
		(end 278.102822 -196.062346)
		(width 0.12954)
		(layer "B.Cu")
		(net "FM_S3M_CPU0_LVC1_GPIO_0")
	)
	(segment
		(start 299.700442 -270.98752)
		(end 299.526452 -270.81353)
		(width 0.12954)
		(layer "B.Cu")
		(net "FM_S3M_CPU0_LVC1_GPIO_0")
	)
	(segment
		(start 292.833298 -269.48765)
		(end 291.893498 -268.54785)
		(width 0.12954)
		(layer "B.Cu")
		(net "FM_S3M_CPU0_LVC1_GPIO_0")
	)
	(segment
		(start 335.48828 -272.200624)
		(end 335.460848 -272.228056)
		(width 0.12954)
		(layer "B.Cu")
		(net "FM_S3M_CPU0_LVC1_GPIO_0")
	)
	(segment
		(start 307.326792 -274.43557)
		(end 306.836572 -273.94535)
		(width 0.12954)
		(layer "B.Cu")
		(net "FM_S3M_CPU0_LVC1_GPIO_0")
	)
	(segment
		(start 350.494346 -272.140934)
		(end 350.479614 -272.14957)
		(width 0.0889)
		(layer "B.Cu")
		(net "FM_S3M_CPU0_LVC1_GPIO_0")
	)
	(segment
		(start 299.526452 -270.81353)
		(end 297.935904 -270.81353)
		(width 0.12954)
		(layer "B.Cu")
		(net "FM_S3M_CPU0_LVC1_GPIO_0")
	)
	(segment
		(start 291.352478 -268.54785)
		(end 290.808918 -268.00429)
		(width 0.12954)
		(layer "B.Cu")
		(net "FM_S3M_CPU0_LVC1_GPIO_0")
	)
	(segment
		(start 278.102822 -196.062346)
		(end 277.422102 -196.062346)
		(width 0.12954)
		(layer "B.Cu")
		(net "FM_S3M_CPU0_LVC1_GPIO_0")
	)
	(segment
		(start 340.156546 -272.140934)
		(end 340.141814 -272.14957)
		(width 0.0889)
		(layer "B.Cu")
		(net "FM_S3M_CPU0_LVC1_GPIO_0")
	)
	(segment
		(start 316.874398 -272.22831)
		(end 314.989718 -274.11299)
		(width 0.12954)
		(layer "B.Cu")
		(net "FM_S3M_CPU0_LVC1_GPIO_0")
	)
	(segment
		(start 300.476158 -270.98752)
		(end 299.700442 -270.98752)
		(width 0.12954)
		(layer "B.Cu")
		(net "FM_S3M_CPU0_LVC1_GPIO_0")
	)
	(segment
		(start 291.893498 -268.54785)
		(end 291.352478 -268.54785)
		(width 0.12954)
		(layer "B.Cu")
		(net "FM_S3M_CPU0_LVC1_GPIO_0")
	)
	(segment
		(start 297.935904 -270.81353)
		(end 297.796204 -270.67383)
		(width 0.12954)
		(layer "B.Cu")
		(net "FM_S3M_CPU0_LVC1_GPIO_0")
	)
	(segment
		(start 336.194908 -272.200624)
		(end 335.48828 -272.200624)
		(width 0.0889)
		(layer "B.Cu")
		(net "FM_S3M_CPU0_LVC1_GPIO_0")
	)
	(segment
		(start 346.735146 -272.140934)
		(end 346.720414 -272.14957)
		(width 0.0889)
		(layer "B.Cu")
		(net "FM_S3M_CPU0_LVC1_GPIO_0")
	)
	(segment
		(start 288.914078 -265.00201)
		(end 288.629598 -264.71753)
		(width 0.12954)
		(layer "B.Cu")
		(net "FM_S3M_CPU0_LVC1_GPIO_0")
	)
	(segment
		(start 276.998938 -195.639182)
		(end 276.998938 -194.209162)
		(width 0.12954)
		(layer "B.Cu")
		(net "FM_S3M_CPU0_LVC1_GPIO_0")
	)
	(segment
		(start 289.643058 -265.00201)
		(end 288.914078 -265.00201)
		(width 0.12954)
		(layer "B.Cu")
		(net "FM_S3M_CPU0_LVC1_GPIO_0")
	)
	(segment
		(start 348.614746 -272.140934)
		(end 348.600014 -272.14957)
		(width 0.0889)
		(layer "B.Cu")
		(net "FM_S3M_CPU0_LVC1_GPIO_0")
	)
	(segment
		(start 288.629598 -264.71753)
		(end 288.629598 -258.073144)
		(width 0.12954)
		(layer "B.Cu")
		(net "FM_S3M_CPU0_LVC1_GPIO_0")
	)
	(segment
		(start 342.036146 -272.140934)
		(end 342.021414 -272.14957)
		(width 0.0889)
		(layer "B.Cu")
		(net "FM_S3M_CPU0_LVC1_GPIO_0")
	)
	(segment
		(start 339.212174 -272.143474)
		(end 339.20176 -272.14957)
		(width 0.0889)
		(layer "B.Cu")
		(net "FM_S3M_CPU0_LVC1_GPIO_0")
	)
	(segment
		(start 293.021258 -269.48765)
		(end 292.833298 -269.48765)
		(width 0.12954)
		(layer "B.Cu")
		(net "FM_S3M_CPU0_LVC1_GPIO_0")
	)
	(segment
		(start 302.166528 -272.67789)
		(end 300.476158 -270.98752)
		(width 0.12954)
		(layer "B.Cu")
		(net "FM_S3M_CPU0_LVC1_GPIO_0")
	)
	(segment
		(start 347.674946 -272.140934)
		(end 347.660214 -272.14957)
		(width 0.0889)
		(layer "B.Cu")
		(net "FM_S3M_CPU0_LVC1_GPIO_0")
	)
	(segment
		(start 303.016158 -272.67789)
		(end 302.166528 -272.67789)
		(width 0.12954)
		(layer "B.Cu")
		(net "FM_S3M_CPU0_LVC1_GPIO_0")
	)
	(segment
		(start 342.975946 -272.140934)
		(end 342.961214 -272.14957)
		(width 0.0889)
		(layer "B.Cu")
		(net "FM_S3M_CPU0_LVC1_GPIO_0")
	)
	(segment
		(start 288.629598 -258.073144)
		(end 284.676342 -254.119888)
		(width 0.12954)
		(layer "B.Cu")
		(net "FM_S3M_CPU0_LVC1_GPIO_0")
	)
	(segment
		(start 295.776904 -270.86687)
		(end 294.400478 -270.86687)
		(width 0.12954)
		(layer "B.Cu")
		(net "FM_S3M_CPU0_LVC1_GPIO_0")
	)
	(segment
		(start 311.492138 -274.11299)
		(end 311.169558 -274.43557)
		(width 0.12954)
		(layer "B.Cu")
		(net "FM_S3M_CPU0_LVC1_GPIO_0")
	)
	(segment
		(start 281.217878 -251.72162)
		(end 281.217878 -196.11975)
		(width 0.12954)
		(layer "B.Cu")
		(net "FM_S3M_CPU0_LVC1_GPIO_0")
	)
	(segment
		(start 338.827364 -272.14957)
		(end 338.812632 -272.140934)
		(width 0.0889)
		(layer "B.Cu")
		(net "FM_S3M_CPU0_LVC1_GPIO_0")
	)
	(segment
		(start 314.989718 -274.11299)
		(end 311.492138 -274.11299)
		(width 0.12954)
		(layer "B.Cu")
		(net "FM_S3M_CPU0_LVC1_GPIO_0")
	)
	(segment
		(start 281.217878 -196.11975)
		(end 280.153618 -195.05549)
		(width 0.12954)
		(layer "B.Cu")
		(net "FM_S3M_CPU0_LVC1_GPIO_0")
	)
	(segment
		(start 336.948018 -272.14957)
		(end 336.937604 -272.143474)
		(width 0.0889)
		(layer "B.Cu")
		(net "FM_S3M_CPU0_LVC1_GPIO_0")
	)
	(segment
		(start 294.400478 -270.86687)
		(end 293.021258 -269.48765)
		(width 0.12954)
		(layer "B.Cu")
		(net "FM_S3M_CPU0_LVC1_GPIO_0")
	)
	(segment
		(start 335.460848 -272.228056)
		(end 318.481202 -272.228056)
		(width 0.12954)
		(layer "B.Cu")
		(net "FM_S3M_CPU0_LVC1_GPIO_0")
	)
	(segment
		(start 277.422102 -196.062346)
		(end 276.998938 -195.639182)
		(width 0.12954)
		(layer "B.Cu")
		(net "FM_S3M_CPU0_LVC1_GPIO_0")
	)
	(segment
		(start 345.405964 -272.14957)
		(end 345.39555 -272.143474)
		(width 0.0889)
		(layer "B.Cu")
		(net "FM_S3M_CPU0_LVC1_GPIO_0")
	)
	(segment
		(start 284.676342 -254.119888)
		(end 283.616146 -254.119888)
		(width 0.12954)
		(layer "B.Cu")
		(net "FM_S3M_CPU0_LVC1_GPIO_0")
	)
	(segment
		(start 311.169558 -274.43557)
		(end 307.326792 -274.43557)
		(width 0.12954)
		(layer "B.Cu")
		(net "FM_S3M_CPU0_LVC1_GPIO_0")
	)
	(segment
		(start 343.915746 -272.140934)
		(end 343.901014 -272.14957)
		(width 0.0889)
		(layer "B.Cu")
		(net "FM_S3M_CPU0_LVC1_GPIO_0")
	)
	(segment
		(start 337.332828 -272.143474)
		(end 337.322414 -272.14957)
		(width 0.0889)
		(layer "B.Cu")
		(net "FM_S3M_CPU0_LVC1_GPIO_0")
	)
	(segment
		(start 351.389188 -272.639282)
		(end 351.32391 -272.574004)
		(width 0.0889)
		(layer "B.Cu")
		(net "FM_S3M_CPU0_LVC1_GPIO_0")
	)
	(segment
		(start 276.998938 -194.209162)
		(end 277.138384 -194.069716)
		(width 0.12954)
		(layer "B.Cu")
		(net "FM_S3M_CPU0_LVC1_GPIO_0")
	)
	(arc
		(start 342.021414 -272.14957)
		(mid 341.834216 -272.199713)
		(end 341.647018 -272.14957)
		(width 0.0889)
		(layer "B.Cu")
		(net "FM_S3M_CPU0_LVC1_GPIO_0")
	)
	(arc
		(start 348.225618 -272.14957)
		(mid 347.951389 -272.073645)
		(end 347.674946 -272.140934)
		(width 0.0889)
		(layer "B.Cu")
		(net "FM_S3M_CPU0_LVC1_GPIO_0")
	)
	(arc
		(start 349.165418 -272.14957)
		(mid 348.891189 -272.073645)
		(end 348.614746 -272.140934)
		(width 0.0889)
		(layer "B.Cu")
		(net "FM_S3M_CPU0_LVC1_GPIO_0")
	)
	(arc
		(start 341.647018 -272.14957)
		(mid 341.372789 -272.073645)
		(end 341.096346 -272.140934)
		(width 0.0889)
		(layer "B.Cu")
		(net "FM_S3M_CPU0_LVC1_GPIO_0")
	)
	(arc
		(start 338.26196 -272.14957)
		(mid 338.074762 -272.199713)
		(end 337.887564 -272.14957)
		(width 0.0889)
		(layer "B.Cu")
		(net "FM_S3M_CPU0_LVC1_GPIO_0")
	)
	(arc
		(start 339.20176 -272.14957)
		(mid 339.014562 -272.199713)
		(end 338.827364 -272.14957)
		(width 0.0889)
		(layer "B.Cu")
		(net "FM_S3M_CPU0_LVC1_GPIO_0")
	)
	(arc
		(start 343.526618 -272.14957)
		(mid 343.252389 -272.073645)
		(end 342.975946 -272.140934)
		(width 0.0889)
		(layer "B.Cu")
		(net "FM_S3M_CPU0_LVC1_GPIO_0")
	)
	(arc
		(start 350.479614 -272.14957)
		(mid 350.292416 -272.199713)
		(end 350.105218 -272.14957)
		(width 0.0889)
		(layer "B.Cu")
		(net "FM_S3M_CPU0_LVC1_GPIO_0")
	)
	(arc
		(start 337.322414 -272.14957)
		(mid 337.135216 -272.199713)
		(end 336.948018 -272.14957)
		(width 0.0889)
		(layer "B.Cu")
		(net "FM_S3M_CPU0_LVC1_GPIO_0")
	)
	(arc
		(start 344.466418 -272.14957)
		(mid 344.192189 -272.073645)
		(end 343.915746 -272.140934)
		(width 0.0889)
		(layer "B.Cu")
		(net "FM_S3M_CPU0_LVC1_GPIO_0")
	)
	(arc
		(start 343.901014 -272.14957)
		(mid 343.713816 -272.199713)
		(end 343.526618 -272.14957)
		(width 0.0889)
		(layer "B.Cu")
		(net "FM_S3M_CPU0_LVC1_GPIO_0")
	)
	(arc
		(start 347.660214 -272.14957)
		(mid 347.473016 -272.199713)
		(end 347.285818 -272.14957)
		(width 0.0889)
		(layer "B.Cu")
		(net "FM_S3M_CPU0_LVC1_GPIO_0")
	)
	(arc
		(start 339.767418 -272.14957)
		(mid 339.490605 -272.073734)
		(end 339.212174 -272.143474)
		(width 0.0889)
		(layer "B.Cu")
		(net "FM_S3M_CPU0_LVC1_GPIO_0")
	)
	(arc
		(start 351.32391 -272.574004)
		(mid 351.023799 -272.137856)
		(end 350.494346 -272.140934)
		(width 0.0889)
		(layer "B.Cu")
		(net "FM_S3M_CPU0_LVC1_GPIO_0")
	)
	(arc
		(start 345.39555 -272.143474)
		(mid 345.117372 -272.073782)
		(end 344.840814 -272.14957)
		(width 0.0889)
		(layer "B.Cu")
		(net "FM_S3M_CPU0_LVC1_GPIO_0")
	)
	(arc
		(start 342.586818 -272.14957)
		(mid 342.312589 -272.073645)
		(end 342.036146 -272.140934)
		(width 0.0889)
		(layer "B.Cu")
		(net "FM_S3M_CPU0_LVC1_GPIO_0")
	)
	(arc
		(start 341.081614 -272.14957)
		(mid 340.894416 -272.199713)
		(end 340.707218 -272.14957)
		(width 0.0889)
		(layer "B.Cu")
		(net "FM_S3M_CPU0_LVC1_GPIO_0")
	)
	(arc
		(start 349.539814 -272.14957)
		(mid 349.352616 -272.199713)
		(end 349.165418 -272.14957)
		(width 0.0889)
		(layer "B.Cu")
		(net "FM_S3M_CPU0_LVC1_GPIO_0")
	)
	(arc
		(start 346.720414 -272.14957)
		(mid 346.533216 -272.199713)
		(end 346.346018 -272.14957)
		(width 0.0889)
		(layer "B.Cu")
		(net "FM_S3M_CPU0_LVC1_GPIO_0")
	)
	(arc
		(start 345.78036 -272.14957)
		(mid 345.593162 -272.199713)
		(end 345.405964 -272.14957)
		(width 0.0889)
		(layer "B.Cu")
		(net "FM_S3M_CPU0_LVC1_GPIO_0")
	)
	(arc
		(start 336.38236 -272.14957)
		(mid 336.292002 -272.187473)
		(end 336.194908 -272.200624)
		(width 0.0889)
		(layer "B.Cu")
		(net "FM_S3M_CPU0_LVC1_GPIO_0")
	)
	(arc
		(start 344.840814 -272.14957)
		(mid 344.653616 -272.199713)
		(end 344.466418 -272.14957)
		(width 0.0889)
		(layer "B.Cu")
		(net "FM_S3M_CPU0_LVC1_GPIO_0")
	)
	(arc
		(start 350.105218 -272.14957)
		(mid 349.830989 -272.073645)
		(end 349.554546 -272.140934)
		(width 0.0889)
		(layer "B.Cu")
		(net "FM_S3M_CPU0_LVC1_GPIO_0")
	)
	(arc
		(start 337.887564 -272.14957)
		(mid 337.611005 -272.073861)
		(end 337.332828 -272.143474)
		(width 0.0889)
		(layer "B.Cu")
		(net "FM_S3M_CPU0_LVC1_GPIO_0")
	)
	(arc
		(start 340.707218 -272.14957)
		(mid 340.432989 -272.073645)
		(end 340.156546 -272.140934)
		(width 0.0889)
		(layer "B.Cu")
		(net "FM_S3M_CPU0_LVC1_GPIO_0")
	)
	(arc
		(start 338.812632 -272.140934)
		(mid 338.536191 -272.073768)
		(end 338.26196 -272.14957)
		(width 0.0889)
		(layer "B.Cu")
		(net "FM_S3M_CPU0_LVC1_GPIO_0")
	)
	(arc
		(start 346.346018 -272.14957)
		(mid 346.069205 -272.073734)
		(end 345.790774 -272.143474)
		(width 0.0889)
		(layer "B.Cu")
		(net "FM_S3M_CPU0_LVC1_GPIO_0")
	)
	(arc
		(start 336.937604 -272.143474)
		(mid 336.659172 -272.07366)
		(end 336.38236 -272.14957)
		(width 0.0889)
		(layer "B.Cu")
		(net "FM_S3M_CPU0_LVC1_GPIO_0")
	)
	(arc
		(start 347.285818 -272.14957)
		(mid 347.011589 -272.073645)
		(end 346.735146 -272.140934)
		(width 0.0889)
		(layer "B.Cu")
		(net "FM_S3M_CPU0_LVC1_GPIO_0")
	)
	(arc
		(start 342.961214 -272.14957)
		(mid 342.774016 -272.199713)
		(end 342.586818 -272.14957)
		(width 0.0889)
		(layer "B.Cu")
		(net "FM_S3M_CPU0_LVC1_GPIO_0")
	)
	(arc
		(start 340.141814 -272.14957)
		(mid 339.954616 -272.199713)
		(end 339.767418 -272.14957)
		(width 0.0889)
		(layer "B.Cu")
		(net "FM_S3M_CPU0_LVC1_GPIO_0")
	)
	(arc
		(start 348.600014 -272.14957)
		(mid 348.412816 -272.199713)
		(end 348.225618 -272.14957)
		(width 0.0889)
		(layer "B.Cu")
		(net "FM_S3M_CPU0_LVC1_GPIO_0")
	)
	(segment
		(start 369.91798 -229.808786)
		(end 369.918234 -229.808532)
		(width 0.12954)
		(layer "F.Cu")
		(net "FM_S3M_CPU0_CPLD_CRC_ERROR")
	)
	(segment
		(start 171.755562 -108.975398)
		(end 171.355512 -108.575348)
		(width 0.12954)
		(layer "F.Cu")
		(net "FM_S3M_CPU0_CPLD_CRC_ERROR")
	)
	(segment
		(start 369.918234 -229.808532)
		(end 369.918234 -229.272846)
		(width 0.12954)
		(layer "F.Cu")
		(net "FM_S3M_CPU0_CPLD_CRC_ERROR")
	)
	(via
		(at 369.918234 -229.272846)
		(size 0.4572)
		(drill 0.2032)
		(layers "F.Cu" "B.Cu")
		(net "FM_S3M_CPU0_CPLD_CRC_ERROR")
	)
	(via
		(at 171.355512 -108.575348)
		(size 0.4572)
		(drill 0.254)
		(layers "F.Cu" "B.Cu")
		(net "FM_S3M_CPU0_CPLD_CRC_ERROR")
	)
	(via
		(at 379.721872 -186.081162)
		(size 0.6604)
		(drill 0.3302)
		(layers "F.Cu" "B.Cu")
		(net "FM_S3M_CPU0_CPLD_CRC_ERROR")
	)
	(via
		(at 210.314286 -149.329902)
		(size 0.508)
		(drill 0.254)
		(layers "F.Cu" "B.Cu")
		(net "FM_S3M_CPU0_CPLD_CRC_ERROR")
	)
	(via
		(at 300.0502 -148.529548)
		(size 0.508)
		(drill 0.254)
		(layers "F.Cu" "B.Cu")
		(net "FM_S3M_CPU0_CPLD_CRC_ERROR")
	)
	(segment
		(start 345.497658 -168.565322)
		(end 351.948496 -168.565322)
		(width 0.12954)
		(layer "B.Cu")
		(net "FM_S3M_CPU0_CPLD_CRC_ERROR")
	)
	(segment
		(start 322.652136 -149.189948)
		(end 328.576178 -151.643842)
		(width 0.12954)
		(layer "B.Cu")
		(net "FM_S3M_CPU0_CPLD_CRC_ERROR")
	)
	(segment
		(start 372.018052 -177.649378)
		(end 373.509286 -179.140612)
		(width 0.12954)
		(layer "B.Cu")
		(net "FM_S3M_CPU0_CPLD_CRC_ERROR")
	)
	(segment
		(start 379.81001 -185.993024)
		(end 379.721872 -186.081162)
		(width 0.12954)
		(layer "B.Cu")
		(net "FM_S3M_CPU0_CPLD_CRC_ERROR")
	)
	(segment
		(start 300.0502 -148.529548)
		(end 300.0502 -147.919948)
		(width 0.12954)
		(layer "B.Cu")
		(net "FM_S3M_CPU0_CPLD_CRC_ERROR")
	)
	(segment
		(start 379.721872 -186.081162)
		(end 380.11608 -186.47537)
		(width 0.12954)
		(layer "B.Cu")
		(net "FM_S3M_CPU0_CPLD_CRC_ERROR")
	)
	(segment
		(start 380.11608 -186.47537)
		(end 380.11608 -187.566554)
		(width 0.12954)
		(layer "B.Cu")
		(net "FM_S3M_CPU0_CPLD_CRC_ERROR")
	)
	(segment
		(start 376.684032 -228.948488)
		(end 376.694446 -228.954584)
		(width 0.0889)
		(layer "B.Cu")
		(net "FM_S3M_CPU0_CPLD_CRC_ERROR")
	)
	(segment
		(start 351.948496 -168.565322)
		(end 353.854512 -170.471338)
		(width 0.12954)
		(layer "B.Cu")
		(net "FM_S3M_CPU0_CPLD_CRC_ERROR")
	)
	(segment
		(start 382.778508 -190.67526)
		(end 382.778508 -189.549024)
		(width 0.12954)
		(layer "B.Cu")
		(net "FM_S3M_CPU0_CPLD_CRC_ERROR")
	)
	(segment
		(start 384.767836 -228.948488)
		(end 385.517136 -228.948488)
		(width 0.0889)
		(layer "B.Cu")
		(net "FM_S3M_CPU0_CPLD_CRC_ERROR")
	)
	(segment
		(start 373.509286 -179.140612)
		(end 374.801638 -179.140612)
		(width 0.12954)
		(layer "B.Cu")
		(net "FM_S3M_CPU0_CPLD_CRC_ERROR")
	)
	(segment
		(start 357.43007 -170.471338)
		(end 361.67314 -174.714408)
		(width 0.12954)
		(layer "B.Cu")
		(net "FM_S3M_CPU0_CPLD_CRC_ERROR")
	)
	(segment
		(start 371.044978 -228.948488)
		(end 371.055392 -228.954584)
		(width 0.0889)
		(layer "B.Cu")
		(net "FM_S3M_CPU0_CPLD_CRC_ERROR")
	)
	(segment
		(start 382.778508 -189.549024)
		(end 381.609854 -188.38037)
		(width 0.12954)
		(layer "B.Cu")
		(net "FM_S3M_CPU0_CPLD_CRC_ERROR")
	)
	(segment
		(start 374.804432 -228.948488)
		(end 374.819164 -228.957124)
		(width 0.0889)
		(layer "B.Cu")
		(net "FM_S3M_CPU0_CPLD_CRC_ERROR")
	)
	(segment
		(start 385.517136 -228.948488)
		(end 386.948426 -228.948488)
		(width 0.12954)
		(layer "B.Cu")
		(net "FM_S3M_CPU0_CPLD_CRC_ERROR")
	)
	(segment
		(start 369.918234 -229.272846)
		(end 370.456968 -229.020116)
		(width 0.0889)
		(layer "B.Cu")
		(net "FM_S3M_CPU0_CPLD_CRC_ERROR")
	)
	(segment
		(start 353.854512 -170.471338)
		(end 357.43007 -170.471338)
		(width 0.12954)
		(layer "B.Cu")
		(net "FM_S3M_CPU0_CPLD_CRC_ERROR")
	)
	(segment
		(start 386.130292 -194.85483)
		(end 384.796284 -194.85483)
		(width 0.12954)
		(layer "B.Cu")
		(net "FM_S3M_CPU0_CPLD_CRC_ERROR")
	)
	(segment
		(start 381.609854 -188.38037)
		(end 381.609854 -188.29401)
		(width 0.12954)
		(layer "B.Cu")
		(net "FM_S3M_CPU0_CPLD_CRC_ERROR")
	)
	(segment
		(start 379.503432 -228.948488)
		(end 379.518164 -228.957124)
		(width 0.0889)
		(layer "B.Cu")
		(net "FM_S3M_CPU0_CPLD_CRC_ERROR")
	)
	(segment
		(start 391.790174 -200.514712)
		(end 386.130292 -194.85483)
		(width 0.12954)
		(layer "B.Cu")
		(net "FM_S3M_CPU0_CPLD_CRC_ERROR")
	)
	(segment
		(start 378.563632 -228.948488)
		(end 378.578364 -228.957124)
		(width 0.0889)
		(layer "B.Cu")
		(net "FM_S3M_CPU0_CPLD_CRC_ERROR")
	)
	(segment
		(start 382.510538 -190.94323)
		(end 382.778508 -190.67526)
		(width 0.12954)
		(layer "B.Cu")
		(net "FM_S3M_CPU0_CPLD_CRC_ERROR")
	)
	(segment
		(start 371.180868 -177.649378)
		(end 372.018052 -177.649378)
		(width 0.12954)
		(layer "B.Cu")
		(net "FM_S3M_CPU0_CPLD_CRC_ERROR")
	)
	(segment
		(start 374.801638 -179.140612)
		(end 379.81001 -184.148984)
		(width 0.12954)
		(layer "B.Cu")
		(net "FM_S3M_CPU0_CPLD_CRC_ERROR")
	)
	(segment
		(start 382.322832 -228.948488)
		(end 382.337564 -228.957124)
		(width 0.0889)
		(layer "B.Cu")
		(net "FM_S3M_CPU0_CPLD_CRC_ERROR")
	)
	(segment
		(start 368.82451 -178.18227)
		(end 370.116862 -178.18227)
		(width 0.12954)
		(layer "B.Cu")
		(net "FM_S3M_CPU0_CPLD_CRC_ERROR")
	)
	(segment
		(start 372.924832 -228.948488)
		(end 372.939564 -228.957124)
		(width 0.0889)
		(layer "B.Cu")
		(net "FM_S3M_CPU0_CPLD_CRC_ERROR")
	)
	(segment
		(start 381.609854 -188.270388)
		(end 381.609854 -188.29401)
		(width 0.12954)
		(layer "B.Cu")
		(net "FM_S3M_CPU0_CPLD_CRC_ERROR")
	)
	(segment
		(start 381.604774 -188.265308)
		(end 381.609854 -188.270388)
		(width 0.12954)
		(layer "B.Cu")
		(net "FM_S3M_CPU0_CPLD_CRC_ERROR")
	)
	(segment
		(start 380.11608 -187.566554)
		(end 380.814834 -188.265308)
		(width 0.12954)
		(layer "B.Cu")
		(net "FM_S3M_CPU0_CPLD_CRC_ERROR")
	)
	(segment
		(start 386.948426 -228.948488)
		(end 391.790174 -224.10674)
		(width 0.12954)
		(layer "B.Cu")
		(net "FM_S3M_CPU0_CPLD_CRC_ERROR")
	)
	(segment
		(start 370.116862 -178.18227)
		(end 370.274342 -178.02479)
		(width 0.12954)
		(layer "B.Cu")
		(net "FM_S3M_CPU0_CPLD_CRC_ERROR")
	)
	(segment
		(start 308.11851 -149.189948)
		(end 322.652136 -149.189948)
		(width 0.12954)
		(layer "B.Cu")
		(net "FM_S3M_CPU0_CPLD_CRC_ERROR")
	)
	(segment
		(start 300.0502 -147.919948)
		(end 300.1772 -147.792948)
		(width 0.12954)
		(layer "B.Cu")
		(net "FM_S3M_CPU0_CPLD_CRC_ERROR")
	)
	(segment
		(start 379.81001 -184.148984)
		(end 379.81001 -185.993024)
		(width 0.12954)
		(layer "B.Cu")
		(net "FM_S3M_CPU0_CPLD_CRC_ERROR")
	)
	(segment
		(start 306.72151 -147.792948)
		(end 308.11851 -149.189948)
		(width 0.12954)
		(layer "B.Cu")
		(net "FM_S3M_CPU0_CPLD_CRC_ERROR")
	)
	(segment
		(start 384.796284 -194.85483)
		(end 382.510538 -192.569084)
		(width 0.12954)
		(layer "B.Cu")
		(net "FM_S3M_CPU0_CPLD_CRC_ERROR")
	)
	(segment
		(start 377.623578 -228.948488)
		(end 377.633992 -228.954584)
		(width 0.0889)
		(layer "B.Cu")
		(net "FM_S3M_CPU0_CPLD_CRC_ERROR")
	)
	(segment
		(start 328.576178 -151.643842)
		(end 345.497658 -168.565322)
		(width 0.12954)
		(layer "B.Cu")
		(net "FM_S3M_CPU0_CPLD_CRC_ERROR")
	)
	(segment
		(start 391.790174 -224.10674)
		(end 391.790174 -200.514712)
		(width 0.12954)
		(layer "B.Cu")
		(net "FM_S3M_CPU0_CPLD_CRC_ERROR")
	)
	(segment
		(start 375.744232 -228.948488)
		(end 375.758964 -228.957124)
		(width 0.0889)
		(layer "B.Cu")
		(net "FM_S3M_CPU0_CPLD_CRC_ERROR")
	)
	(segment
		(start 300.1772 -147.792948)
		(end 306.72151 -147.792948)
		(width 0.12954)
		(layer "B.Cu")
		(net "FM_S3M_CPU0_CPLD_CRC_ERROR")
	)
	(segment
		(start 380.814834 -188.265308)
		(end 381.604774 -188.265308)
		(width 0.12954)
		(layer "B.Cu")
		(net "FM_S3M_CPU0_CPLD_CRC_ERROR")
	)
	(segment
		(start 382.510538 -192.569084)
		(end 382.510538 -190.94323)
		(width 0.12954)
		(layer "B.Cu")
		(net "FM_S3M_CPU0_CPLD_CRC_ERROR")
	)
	(segment
		(start 371.985032 -228.948488)
		(end 371.999764 -228.957124)
		(width 0.0889)
		(layer "B.Cu")
		(net "FM_S3M_CPU0_CPLD_CRC_ERROR")
	)
	(segment
		(start 361.67314 -174.714408)
		(end 365.356648 -174.714408)
		(width 0.12954)
		(layer "B.Cu")
		(net "FM_S3M_CPU0_CPLD_CRC_ERROR")
	)
	(segment
		(start 365.356648 -174.714408)
		(end 368.82451 -178.18227)
		(width 0.12954)
		(layer "B.Cu")
		(net "FM_S3M_CPU0_CPLD_CRC_ERROR")
	)
	(segment
		(start 370.274342 -178.02479)
		(end 371.180868 -177.649378)
		(width 0.12954)
		(layer "B.Cu")
		(net "FM_S3M_CPU0_CPLD_CRC_ERROR")
	)
	(arc
		(start 370.456968 -229.020116)
		(mid 370.567378 -228.995048)
		(end 370.670582 -228.948488)
		(width 0.0889)
		(layer "B.Cu")
		(net "FM_S3M_CPU0_CPLD_CRC_ERROR")
	)
	(arc
		(start 380.068836 -228.948488)
		(mid 380.256034 -228.898345)
		(end 380.443232 -228.948488)
		(width 0.0889)
		(layer "B.Cu")
		(net "FM_S3M_CPU0_CPLD_CRC_ERROR")
	)
	(arc
		(start 383.262632 -228.948488)
		(mid 383.545334 -229.024264)
		(end 383.828036 -228.948488)
		(width 0.0889)
		(layer "B.Cu")
		(net "FM_S3M_CPU0_CPLD_CRC_ERROR")
	)
	(arc
		(start 384.202432 -228.948488)
		(mid 384.485134 -229.024264)
		(end 384.767836 -228.948488)
		(width 0.0889)
		(layer "B.Cu")
		(net "FM_S3M_CPU0_CPLD_CRC_ERROR")
	)
	(arc
		(start 378.578364 -228.957124)
		(mid 378.854839 -229.024444)
		(end 379.129036 -228.948488)
		(width 0.0889)
		(layer "B.Cu")
		(net "FM_S3M_CPU0_CPLD_CRC_ERROR")
	)
	(arc
		(start 371.999764 -228.957124)
		(mid 372.276239 -229.024444)
		(end 372.550436 -228.948488)
		(width 0.0889)
		(layer "B.Cu")
		(net "FM_S3M_CPU0_CPLD_CRC_ERROR")
	)
	(arc
		(start 381.383032 -228.948488)
		(mid 381.665734 -229.024264)
		(end 381.948436 -228.948488)
		(width 0.0889)
		(layer "B.Cu")
		(net "FM_S3M_CPU0_CPLD_CRC_ERROR")
	)
	(arc
		(start 383.828036 -228.948488)
		(mid 384.015234 -228.898345)
		(end 384.202432 -228.948488)
		(width 0.0889)
		(layer "B.Cu")
		(net "FM_S3M_CPU0_CPLD_CRC_ERROR")
	)
	(arc
		(start 374.430036 -228.948488)
		(mid 374.617234 -228.898345)
		(end 374.804432 -228.948488)
		(width 0.0889)
		(layer "B.Cu")
		(net "FM_S3M_CPU0_CPLD_CRC_ERROR")
	)
	(arc
		(start 382.337564 -228.957124)
		(mid 382.614039 -229.024444)
		(end 382.888236 -228.948488)
		(width 0.0889)
		(layer "B.Cu")
		(net "FM_S3M_CPU0_CPLD_CRC_ERROR")
	)
	(arc
		(start 370.670582 -228.948488)
		(mid 370.85778 -228.898345)
		(end 371.044978 -228.948488)
		(width 0.0889)
		(layer "B.Cu")
		(net "FM_S3M_CPU0_CPLD_CRC_ERROR")
	)
	(arc
		(start 372.550436 -228.948488)
		(mid 372.737634 -228.898345)
		(end 372.924832 -228.948488)
		(width 0.0889)
		(layer "B.Cu")
		(net "FM_S3M_CPU0_CPLD_CRC_ERROR")
	)
	(arc
		(start 376.309636 -228.948488)
		(mid 376.496834 -228.898345)
		(end 376.684032 -228.948488)
		(width 0.0889)
		(layer "B.Cu")
		(net "FM_S3M_CPU0_CPLD_CRC_ERROR")
	)
	(arc
		(start 371.610636 -228.948488)
		(mid 371.797834 -228.898345)
		(end 371.985032 -228.948488)
		(width 0.0889)
		(layer "B.Cu")
		(net "FM_S3M_CPU0_CPLD_CRC_ERROR")
	)
	(arc
		(start 377.633992 -228.954584)
		(mid 377.912424 -229.02443)
		(end 378.189236 -228.948488)
		(width 0.0889)
		(layer "B.Cu")
		(net "FM_S3M_CPU0_CPLD_CRC_ERROR")
	)
	(arc
		(start 374.819164 -228.957124)
		(mid 375.095639 -229.024444)
		(end 375.369836 -228.948488)
		(width 0.0889)
		(layer "B.Cu")
		(net "FM_S3M_CPU0_CPLD_CRC_ERROR")
	)
	(arc
		(start 376.694446 -228.954584)
		(mid 376.972624 -229.024307)
		(end 377.249182 -228.948488)
		(width 0.0889)
		(layer "B.Cu")
		(net "FM_S3M_CPU0_CPLD_CRC_ERROR")
	)
	(arc
		(start 382.888236 -228.948488)
		(mid 383.075434 -228.898345)
		(end 383.262632 -228.948488)
		(width 0.0889)
		(layer "B.Cu")
		(net "FM_S3M_CPU0_CPLD_CRC_ERROR")
	)
	(arc
		(start 372.939564 -228.957124)
		(mid 373.216039 -229.024444)
		(end 373.490236 -228.948488)
		(width 0.0889)
		(layer "B.Cu")
		(net "FM_S3M_CPU0_CPLD_CRC_ERROR")
	)
	(arc
		(start 371.055392 -228.954584)
		(mid 371.333824 -229.02443)
		(end 371.610636 -228.948488)
		(width 0.0889)
		(layer "B.Cu")
		(net "FM_S3M_CPU0_CPLD_CRC_ERROR")
	)
	(arc
		(start 373.490236 -228.948488)
		(mid 373.677434 -228.898345)
		(end 373.864632 -228.948488)
		(width 0.0889)
		(layer "B.Cu")
		(net "FM_S3M_CPU0_CPLD_CRC_ERROR")
	)
	(arc
		(start 377.249182 -228.948488)
		(mid 377.43638 -228.898345)
		(end 377.623578 -228.948488)
		(width 0.0889)
		(layer "B.Cu")
		(net "FM_S3M_CPU0_CPLD_CRC_ERROR")
	)
	(arc
		(start 380.443232 -228.948488)
		(mid 380.725934 -229.024264)
		(end 381.008636 -228.948488)
		(width 0.0889)
		(layer "B.Cu")
		(net "FM_S3M_CPU0_CPLD_CRC_ERROR")
	)
	(arc
		(start 375.369836 -228.948488)
		(mid 375.557034 -228.898345)
		(end 375.744232 -228.948488)
		(width 0.0889)
		(layer "B.Cu")
		(net "FM_S3M_CPU0_CPLD_CRC_ERROR")
	)
	(arc
		(start 381.948436 -228.948488)
		(mid 382.135634 -228.898345)
		(end 382.322832 -228.948488)
		(width 0.0889)
		(layer "B.Cu")
		(net "FM_S3M_CPU0_CPLD_CRC_ERROR")
	)
	(arc
		(start 378.189236 -228.948488)
		(mid 378.376434 -228.898345)
		(end 378.563632 -228.948488)
		(width 0.0889)
		(layer "B.Cu")
		(net "FM_S3M_CPU0_CPLD_CRC_ERROR")
	)
	(arc
		(start 375.758964 -228.957124)
		(mid 376.035439 -229.024444)
		(end 376.309636 -228.948488)
		(width 0.0889)
		(layer "B.Cu")
		(net "FM_S3M_CPU0_CPLD_CRC_ERROR")
	)
	(arc
		(start 379.518164 -228.957124)
		(mid 379.794639 -229.024444)
		(end 380.068836 -228.948488)
		(width 0.0889)
		(layer "B.Cu")
		(net "FM_S3M_CPU0_CPLD_CRC_ERROR")
	)
	(arc
		(start 381.008636 -228.948488)
		(mid 381.195834 -228.898345)
		(end 381.383032 -228.948488)
		(width 0.0889)
		(layer "B.Cu")
		(net "FM_S3M_CPU0_CPLD_CRC_ERROR")
	)
	(arc
		(start 373.864632 -228.948488)
		(mid 374.147334 -229.024264)
		(end 374.430036 -228.948488)
		(width 0.0889)
		(layer "B.Cu")
		(net "FM_S3M_CPU0_CPLD_CRC_ERROR")
	)
	(arc
		(start 379.129036 -228.948488)
		(mid 379.316234 -228.898345)
		(end 379.503432 -228.948488)
		(width 0.0889)
		(layer "B.Cu")
		(net "FM_S3M_CPU0_CPLD_CRC_ERROR")
	)
	(segment
		(start 182.95874 -118.405148)
		(end 183.12892 -118.575328)
		(width 0.127)
		(layer "In2.Cu")
		(net "FM_S3M_CPU0_CPLD_CRC_ERROR")
	)
	(segment
		(start 183.12892 -118.575328)
		(end 183.53532 -118.575328)
		(width 0.127)
		(layer "In2.Cu")
		(net "FM_S3M_CPU0_CPLD_CRC_ERROR")
	)
	(segment
		(start 183.75122 -119.129048)
		(end 183.99633 -119.374158)
		(width 0.127)
		(layer "In2.Cu")
		(net "FM_S3M_CPU0_CPLD_CRC_ERROR")
	)
	(segment
		(start 171.759372 -110.35538)
		(end 171.9834 -110.579408)
		(width 0.127)
		(layer "In2.Cu")
		(net "FM_S3M_CPU0_CPLD_CRC_ERROR")
	)
	(segment
		(start 184.55132 -119.936768)
		(end 184.79262 -120.178068)
		(width 0.127)
		(layer "In2.Cu")
		(net "FM_S3M_CPU0_CPLD_CRC_ERROR")
	)
	(segment
		(start 185.3565 -120.810528)
		(end 185.52668 -120.980708)
		(width 0.127)
		(layer "In2.Cu")
		(net "FM_S3M_CPU0_CPLD_CRC_ERROR")
	)
	(segment
		(start 186.96178 -122.392948)
		(end 187.56503 -122.996198)
		(width 0.127)
		(layer "In2.Cu")
		(net "FM_S3M_CPU0_CPLD_CRC_ERROR")
	)
	(segment
		(start 189.99708 -126.835916)
		(end 196.67093 -133.509766)
		(width 0.127)
		(layer "In2.Cu")
		(net "FM_S3M_CPU0_CPLD_CRC_ERROR")
	)
	(segment
		(start 184.55132 -119.609108)
		(end 184.55132 -119.936768)
		(width 0.127)
		(layer "In2.Cu")
		(net "FM_S3M_CPU0_CPLD_CRC_ERROR")
	)
	(segment
		(start 196.67093 -135.188198)
		(end 197.10908 -135.626348)
		(width 0.127)
		(layer "In2.Cu")
		(net "FM_S3M_CPU0_CPLD_CRC_ERROR")
	)
	(segment
		(start 173.35246 -110.795308)
		(end 173.35246 -112.809528)
		(width 0.127)
		(layer "In2.Cu")
		(net "FM_S3M_CPU0_CPLD_CRC_ERROR")
	)
	(segment
		(start 186.06262 -120.980708)
		(end 186.96178 -121.879868)
		(width 0.127)
		(layer "In2.Cu")
		(net "FM_S3M_CPU0_CPLD_CRC_ERROR")
	)
	(segment
		(start 189.99708 -124.983748)
		(end 189.99708 -126.835916)
		(width 0.127)
		(layer "In2.Cu")
		(net "FM_S3M_CPU0_CPLD_CRC_ERROR")
	)
	(segment
		(start 171.355512 -108.575348)
		(end 171.759372 -108.979208)
		(width 0.127)
		(layer "In2.Cu")
		(net "FM_S3M_CPU0_CPLD_CRC_ERROR")
	)
	(segment
		(start 171.9834 -110.579408)
		(end 173.13656 -110.579408)
		(width 0.127)
		(layer "In2.Cu")
		(net "FM_S3M_CPU0_CPLD_CRC_ERROR")
	)
	(segment
		(start 182.95874 -117.907308)
		(end 182.95874 -118.405148)
		(width 0.127)
		(layer "In2.Cu")
		(net "FM_S3M_CPU0_CPLD_CRC_ERROR")
	)
	(segment
		(start 183.99633 -119.374158)
		(end 184.31637 -119.374158)
		(width 0.127)
		(layer "In2.Cu")
		(net "FM_S3M_CPU0_CPLD_CRC_ERROR")
	)
	(segment
		(start 197.10908 -135.626348)
		(end 197.40372 -135.626348)
		(width 0.127)
		(layer "In2.Cu")
		(net "FM_S3M_CPU0_CPLD_CRC_ERROR")
	)
	(segment
		(start 184.79262 -120.178068)
		(end 185.12028 -120.178068)
		(width 0.127)
		(layer "In2.Cu")
		(net "FM_S3M_CPU0_CPLD_CRC_ERROR")
	)
	(segment
		(start 183.53532 -118.575328)
		(end 183.75122 -118.791228)
		(width 0.127)
		(layer "In2.Cu")
		(net "FM_S3M_CPU0_CPLD_CRC_ERROR")
	)
	(segment
		(start 185.52668 -120.980708)
		(end 186.06262 -120.980708)
		(width 0.127)
		(layer "In2.Cu")
		(net "FM_S3M_CPU0_CPLD_CRC_ERROR")
	)
	(segment
		(start 174.28464 -113.741708)
		(end 177.9143 -113.741708)
		(width 0.127)
		(layer "In2.Cu")
		(net "FM_S3M_CPU0_CPLD_CRC_ERROR")
	)
	(segment
		(start 188.00953 -122.996198)
		(end 189.99708 -124.983748)
		(width 0.127)
		(layer "In2.Cu")
		(net "FM_S3M_CPU0_CPLD_CRC_ERROR")
	)
	(segment
		(start 186.96178 -121.879868)
		(end 186.96178 -122.392948)
		(width 0.127)
		(layer "In2.Cu")
		(net "FM_S3M_CPU0_CPLD_CRC_ERROR")
	)
	(segment
		(start 197.40372 -135.626348)
		(end 210.314286 -148.536914)
		(width 0.127)
		(layer "In2.Cu")
		(net "FM_S3M_CPU0_CPLD_CRC_ERROR")
	)
	(segment
		(start 182.8292 -117.777768)
		(end 182.95874 -117.907308)
		(width 0.127)
		(layer "In2.Cu")
		(net "FM_S3M_CPU0_CPLD_CRC_ERROR")
	)
	(segment
		(start 187.56503 -122.996198)
		(end 188.00953 -122.996198)
		(width 0.127)
		(layer "In2.Cu")
		(net "FM_S3M_CPU0_CPLD_CRC_ERROR")
	)
	(segment
		(start 179.0446 -116.970048)
		(end 182.001922 -116.970048)
		(width 0.127)
		(layer "In2.Cu")
		(net "FM_S3M_CPU0_CPLD_CRC_ERROR")
	)
	(segment
		(start 182.1561 -117.662198)
		(end 182.27167 -117.777768)
		(width 0.127)
		(layer "In2.Cu")
		(net "FM_S3M_CPU0_CPLD_CRC_ERROR")
	)
	(segment
		(start 171.759372 -108.979208)
		(end 171.759372 -110.35538)
		(width 0.127)
		(layer "In2.Cu")
		(net "FM_S3M_CPU0_CPLD_CRC_ERROR")
	)
	(segment
		(start 178.38928 -114.216688)
		(end 178.38928 -116.314728)
		(width 0.127)
		(layer "In2.Cu")
		(net "FM_S3M_CPU0_CPLD_CRC_ERROR")
	)
	(segment
		(start 177.9143 -113.741708)
		(end 178.38928 -114.216688)
		(width 0.127)
		(layer "In2.Cu")
		(net "FM_S3M_CPU0_CPLD_CRC_ERROR")
	)
	(segment
		(start 210.314286 -148.536914)
		(end 210.314286 -149.329902)
		(width 0.127)
		(layer "In2.Cu")
		(net "FM_S3M_CPU0_CPLD_CRC_ERROR")
	)
	(segment
		(start 185.12028 -120.178068)
		(end 185.3565 -120.414288)
		(width 0.127)
		(layer "In2.Cu")
		(net "FM_S3M_CPU0_CPLD_CRC_ERROR")
	)
	(segment
		(start 184.31637 -119.374158)
		(end 184.55132 -119.609108)
		(width 0.127)
		(layer "In2.Cu")
		(net "FM_S3M_CPU0_CPLD_CRC_ERROR")
	)
	(segment
		(start 183.75122 -118.791228)
		(end 183.75122 -119.129048)
		(width 0.127)
		(layer "In2.Cu")
		(net "FM_S3M_CPU0_CPLD_CRC_ERROR")
	)
	(segment
		(start 196.67093 -133.509766)
		(end 196.67093 -135.188198)
		(width 0.127)
		(layer "In2.Cu")
		(net "FM_S3M_CPU0_CPLD_CRC_ERROR")
	)
	(segment
		(start 173.13656 -110.579408)
		(end 173.35246 -110.795308)
		(width 0.127)
		(layer "In2.Cu")
		(net "FM_S3M_CPU0_CPLD_CRC_ERROR")
	)
	(segment
		(start 185.3565 -120.414288)
		(end 185.3565 -120.810528)
		(width 0.127)
		(layer "In2.Cu")
		(net "FM_S3M_CPU0_CPLD_CRC_ERROR")
	)
	(segment
		(start 182.27167 -117.777768)
		(end 182.8292 -117.777768)
		(width 0.127)
		(layer "In2.Cu")
		(net "FM_S3M_CPU0_CPLD_CRC_ERROR")
	)
	(segment
		(start 182.001922 -116.970048)
		(end 182.1561 -117.124226)
		(width 0.127)
		(layer "In2.Cu")
		(net "FM_S3M_CPU0_CPLD_CRC_ERROR")
	)
	(segment
		(start 173.35246 -112.809528)
		(end 174.28464 -113.741708)
		(width 0.127)
		(layer "In2.Cu")
		(net "FM_S3M_CPU0_CPLD_CRC_ERROR")
	)
	(segment
		(start 178.38928 -116.314728)
		(end 179.0446 -116.970048)
		(width 0.127)
		(layer "In2.Cu")
		(net "FM_S3M_CPU0_CPLD_CRC_ERROR")
	)
	(segment
		(start 182.1561 -117.124226)
		(end 182.1561 -117.662198)
		(width 0.127)
		(layer "In2.Cu")
		(net "FM_S3M_CPU0_CPLD_CRC_ERROR")
	)
	(segment
		(start 218.133168 -149.189948)
		(end 210.45424 -149.189948)
		(width 0.127)
		(layer "In6.Cu")
		(net "FM_S3M_CPU0_CPLD_CRC_ERROR")
	)
	(segment
		(start 210.45424 -149.189948)
		(end 210.314286 -149.329902)
		(width 0.127)
		(layer "In6.Cu")
		(net "FM_S3M_CPU0_CPLD_CRC_ERROR")
	)
	(segment
		(start 267.168376 -150.062438)
		(end 265.60653 -148.500592)
		(width 0.127)
		(layer "In6.Cu")
		(net "FM_S3M_CPU0_CPLD_CRC_ERROR")
	)
	(segment
		(start 284.48 -151.348948)
		(end 281.050492 -147.91944)
		(width 0.127)
		(layer "In6.Cu")
		(net "FM_S3M_CPU0_CPLD_CRC_ERROR")
	)
	(segment
		(start 265.60653 -148.500592)
		(end 254.729234 -148.500592)
		(width 0.127)
		(layer "In6.Cu")
		(net "FM_S3M_CPU0_CPLD_CRC_ERROR")
	)
	(segment
		(start 253.587504 -149.642322)
		(end 243.31295 -149.642322)
		(width 0.127)
		(layer "In6.Cu")
		(net "FM_S3M_CPU0_CPLD_CRC_ERROR")
	)
	(segment
		(start 297.5737 -150.396448)
		(end 294.322754 -150.396448)
		(width 0.127)
		(layer "In6.Cu")
		(net "FM_S3M_CPU0_CPLD_CRC_ERROR")
	)
	(segment
		(start 294.322754 -150.396448)
		(end 293.370254 -151.348948)
		(width 0.127)
		(layer "In6.Cu")
		(net "FM_S3M_CPU0_CPLD_CRC_ERROR")
	)
	(segment
		(start 293.370254 -151.348948)
		(end 284.48 -151.348948)
		(width 0.127)
		(layer "In6.Cu")
		(net "FM_S3M_CPU0_CPLD_CRC_ERROR")
	)
	(segment
		(start 254.729234 -148.500592)
		(end 253.587504 -149.642322)
		(width 0.127)
		(layer "In6.Cu")
		(net "FM_S3M_CPU0_CPLD_CRC_ERROR")
	)
	(segment
		(start 299.14596 -149.433788)
		(end 298.53636 -149.433788)
		(width 0.127)
		(layer "In6.Cu")
		(net "FM_S3M_CPU0_CPLD_CRC_ERROR")
	)
	(segment
		(start 281.050492 -147.91944)
		(end 274.200874 -147.91944)
		(width 0.127)
		(layer "In6.Cu")
		(net "FM_S3M_CPU0_CPLD_CRC_ERROR")
	)
	(segment
		(start 243.31295 -149.642322)
		(end 242.23599 -148.565362)
		(width 0.127)
		(layer "In6.Cu")
		(net "FM_S3M_CPU0_CPLD_CRC_ERROR")
	)
	(segment
		(start 298.53636 -149.433788)
		(end 297.5737 -150.396448)
		(width 0.127)
		(layer "In6.Cu")
		(net "FM_S3M_CPU0_CPLD_CRC_ERROR")
	)
	(segment
		(start 218.757754 -148.565362)
		(end 218.133168 -149.189948)
		(width 0.127)
		(layer "In6.Cu")
		(net "FM_S3M_CPU0_CPLD_CRC_ERROR")
	)
	(segment
		(start 300.0502 -148.529548)
		(end 299.14596 -149.433788)
		(width 0.127)
		(layer "In6.Cu")
		(net "FM_S3M_CPU0_CPLD_CRC_ERROR")
	)
	(segment
		(start 274.200874 -147.91944)
		(end 272.057876 -150.062438)
		(width 0.127)
		(layer "In6.Cu")
		(net "FM_S3M_CPU0_CPLD_CRC_ERROR")
	)
	(segment
		(start 242.23599 -148.565362)
		(end 218.757754 -148.565362)
		(width 0.127)
		(layer "In6.Cu")
		(net "FM_S3M_CPU0_CPLD_CRC_ERROR")
	)
	(segment
		(start 272.057876 -150.062438)
		(end 267.168376 -150.062438)
		(width 0.127)
		(layer "In6.Cu")
		(net "FM_S3M_CPU0_CPLD_CRC_ERROR")
	)
	(segment
		(start 365.328962 -268.033754)
		(end 365.328962 -268.569694)
		(width 0.12954)
		(layer "F.Cu")
		(net "FM_S3M_CPU0_CPLD_CONFIG_N")
	)
	(via
		(at 398.205198 -263.35101)
		(size 0.6604)
		(drill 0.3302)
		(layers "F.Cu" "B.Cu")
		(net "FM_S3M_CPU0_CPLD_CONFIG_N")
	)
	(via
		(at 365.328962 -268.569694)
		(size 0.4572)
		(drill 0.2032)
		(layers "F.Cu" "B.Cu")
		(net "FM_S3M_CPU0_CPLD_CONFIG_N")
	)
	(segment
		(start 412.599378 -246.17045)
		(end 412.137098 -246.63273)
		(width 0.12954)
		(layer "B.Cu")
		(net "FM_S3M_CPU0_CPLD_CONFIG_N")
	)
	(segment
		(start 381.507746 -268.885416)
		(end 381.493014 -268.894052)
		(width 0.0889)
		(layer "B.Cu")
		(net "FM_S3M_CPU0_CPLD_CONFIG_N")
	)
	(segment
		(start 382.447546 -268.885416)
		(end 382.432814 -268.894052)
		(width 0.0889)
		(layer "B.Cu")
		(net "FM_S3M_CPU0_CPLD_CONFIG_N")
	)
	(segment
		(start 404.600918 -256.95529)
		(end 398.205198 -263.35101)
		(width 0.12954)
		(layer "B.Cu")
		(net "FM_S3M_CPU0_CPLD_CONFIG_N")
	)
	(segment
		(start 378.688346 -268.885416)
		(end 378.673614 -268.894052)
		(width 0.0889)
		(layer "B.Cu")
		(net "FM_S3M_CPU0_CPLD_CONFIG_N")
	)
	(segment
		(start 371.165374 -268.887956)
		(end 371.15496 -268.894052)
		(width 0.0889)
		(layer "B.Cu")
		(net "FM_S3M_CPU0_CPLD_CONFIG_N")
	)
	(segment
		(start 410.618178 -246.95277)
		(end 409.119578 -246.95277)
		(width 0.12954)
		(layer "B.Cu")
		(net "FM_S3M_CPU0_CPLD_CONFIG_N")
	)
	(segment
		(start 369.840764 -268.894052)
		(end 369.83035 -268.887956)
		(width 0.0889)
		(layer "B.Cu")
		(net "FM_S3M_CPU0_CPLD_CONFIG_N")
	)
	(segment
		(start 367.961164 -268.894052)
		(end 367.946432 -268.885416)
		(width 0.0889)
		(layer "B.Cu")
		(net "FM_S3M_CPU0_CPLD_CONFIG_N")
	)
	(segment
		(start 409.119578 -246.95277)
		(end 408.339798 -247.73255)
		(width 0.12954)
		(layer "B.Cu")
		(net "FM_S3M_CPU0_CPLD_CONFIG_N")
	)
	(segment
		(start 416.287712 -240.561876)
		(end 414.786318 -242.06327)
		(width 0.12954)
		(layer "B.Cu")
		(net "FM_S3M_CPU0_CPLD_CONFIG_N")
	)
	(segment
		(start 392.67765 -268.878558)
		(end 390.392158 -268.878558)
		(width 0.12954)
		(layer "B.Cu")
		(net "FM_S3M_CPU0_CPLD_CONFIG_N")
	)
	(segment
		(start 374.929146 -268.885416)
		(end 374.914414 -268.894052)
		(width 0.0889)
		(layer "B.Cu")
		(net "FM_S3M_CPU0_CPLD_CONFIG_N")
	)
	(segment
		(start 368.339878 -268.891512)
		(end 368.33556 -268.894052)
		(width 0.0889)
		(layer "B.Cu")
		(net "FM_S3M_CPU0_CPLD_CONFIG_N")
	)
	(segment
		(start 379.628146 -268.885416)
		(end 379.613414 -268.894052)
		(width 0.0889)
		(layer "B.Cu")
		(net "FM_S3M_CPU0_CPLD_CONFIG_N")
	)
	(segment
		(start 366.081818 -268.894052)
		(end 366.071404 -268.887956)
		(width 0.0889)
		(layer "B.Cu")
		(net "FM_S3M_CPU0_CPLD_CONFIG_N")
	)
	(segment
		(start 414.179258 -246.17045)
		(end 412.599378 -246.17045)
		(width 0.12954)
		(layer "B.Cu")
		(net "FM_S3M_CPU0_CPLD_CONFIG_N")
	)
	(segment
		(start 384.755136 -268.878304)
		(end 384.194558 -268.93901)
		(width 0.0889)
		(layer "B.Cu")
		(net "FM_S3M_CPU0_CPLD_CONFIG_N")
	)
	(segment
		(start 377.748546 -268.885416)
		(end 377.733814 -268.894052)
		(width 0.0889)
		(layer "B.Cu")
		(net "FM_S3M_CPU0_CPLD_CONFIG_N")
	)
	(segment
		(start 383.96545 -268.910054)
		(end 383.937764 -268.894052)
		(width 0.0889)
		(layer "B.Cu")
		(net "FM_S3M_CPU0_CPLD_CONFIG_N")
	)
	(segment
		(start 408.339798 -247.73255)
		(end 405.578818 -247.73255)
		(width 0.12954)
		(layer "B.Cu")
		(net "FM_S3M_CPU0_CPLD_CONFIG_N")
	)
	(segment
		(start 412.137098 -246.63273)
		(end 410.938218 -246.63273)
		(width 0.12954)
		(layer "B.Cu")
		(net "FM_S3M_CPU0_CPLD_CONFIG_N")
	)
	(segment
		(start 367.021364 -268.894052)
		(end 367.01095 -268.887956)
		(width 0.0889)
		(layer "B.Cu")
		(net "FM_S3M_CPU0_CPLD_CONFIG_N")
	)
	(segment
		(start 405.578818 -247.73255)
		(end 404.600918 -248.71045)
		(width 0.12954)
		(layer "B.Cu")
		(net "FM_S3M_CPU0_CPLD_CONFIG_N")
	)
	(segment
		(start 376.808746 -268.885416)
		(end 376.794014 -268.894052)
		(width 0.0889)
		(layer "B.Cu")
		(net "FM_S3M_CPU0_CPLD_CONFIG_N")
	)
	(segment
		(start 404.600918 -248.71045)
		(end 404.600918 -256.95529)
		(width 0.12954)
		(layer "B.Cu")
		(net "FM_S3M_CPU0_CPLD_CONFIG_N")
	)
	(segment
		(start 375.868946 -268.885416)
		(end 375.854214 -268.894052)
		(width 0.0889)
		(layer "B.Cu")
		(net "FM_S3M_CPU0_CPLD_CONFIG_N")
	)
	(segment
		(start 368.345974 -268.887956)
		(end 368.339878 -268.891512)
		(width 0.0889)
		(layer "B.Cu")
		(net "FM_S3M_CPU0_CPLD_CONFIG_N")
	)
	(segment
		(start 410.938218 -246.63273)
		(end 410.618178 -246.95277)
		(width 0.12954)
		(layer "B.Cu")
		(net "FM_S3M_CPU0_CPLD_CONFIG_N")
	)
	(segment
		(start 416.287712 -193.48958)
		(end 416.287712 -240.561876)
		(width 0.12954)
		(layer "B.Cu")
		(net "FM_S3M_CPU0_CPLD_CONFIG_N")
	)
	(segment
		(start 414.786318 -245.56339)
		(end 414.179258 -246.17045)
		(width 0.12954)
		(layer "B.Cu")
		(net "FM_S3M_CPU0_CPLD_CONFIG_N")
	)
	(segment
		(start 373.049546 -268.885416)
		(end 373.034814 -268.894052)
		(width 0.0889)
		(layer "B.Cu")
		(net "FM_S3M_CPU0_CPLD_CONFIG_N")
	)
	(segment
		(start 390.391904 -268.878304)
		(end 384.755136 -268.878304)
		(width 0.12954)
		(layer "B.Cu")
		(net "FM_S3M_CPU0_CPLD_CONFIG_N")
	)
	(segment
		(start 372.109746 -268.885416)
		(end 372.095014 -268.894052)
		(width 0.0889)
		(layer "B.Cu")
		(net "FM_S3M_CPU0_CPLD_CONFIG_N")
	)
	(segment
		(start 390.392158 -268.878558)
		(end 390.391904 -268.878304)
		(width 0.12954)
		(layer "B.Cu")
		(net "FM_S3M_CPU0_CPLD_CONFIG_N")
	)
	(segment
		(start 398.205198 -263.35101)
		(end 392.67765 -268.878558)
		(width 0.12954)
		(layer "B.Cu")
		(net "FM_S3M_CPU0_CPLD_CONFIG_N")
	)
	(segment
		(start 383.383028 -268.887956)
		(end 383.372614 -268.894052)
		(width 0.0889)
		(layer "B.Cu")
		(net "FM_S3M_CPU0_CPLD_CONFIG_N")
	)
	(segment
		(start 373.989346 -268.885416)
		(end 373.974614 -268.894052)
		(width 0.0889)
		(layer "B.Cu")
		(net "FM_S3M_CPU0_CPLD_CONFIG_N")
	)
	(segment
		(start 365.485426 -268.840712)
		(end 365.328962 -268.569694)
		(width 0.0889)
		(layer "B.Cu")
		(net "FM_S3M_CPU0_CPLD_CONFIG_N")
	)
	(segment
		(start 414.786318 -242.06327)
		(end 414.786318 -245.56339)
		(width 0.12954)
		(layer "B.Cu")
		(net "FM_S3M_CPU0_CPLD_CONFIG_N")
	)
	(segment
		(start 365.57458 -268.864588)
		(end 365.485426 -268.840712)
		(width 0.0889)
		(layer "B.Cu")
		(net "FM_S3M_CPU0_CPLD_CONFIG_N")
	)
	(arc
		(start 383.937764 -268.894052)
		(mid 383.661205 -268.818309)
		(end 383.383028 -268.887956)
		(width 0.0889)
		(layer "B.Cu")
		(net "FM_S3M_CPU0_CPLD_CONFIG_N")
	)
	(arc
		(start 375.479818 -268.894052)
		(mid 375.205619 -268.818217)
		(end 374.929146 -268.885416)
		(width 0.0889)
		(layer "B.Cu")
		(net "FM_S3M_CPU0_CPLD_CONFIG_N")
	)
	(arc
		(start 381.493014 -268.894052)
		(mid 381.305816 -268.944195)
		(end 381.118618 -268.894052)
		(width 0.0889)
		(layer "B.Cu")
		(net "FM_S3M_CPU0_CPLD_CONFIG_N")
	)
	(arc
		(start 367.946432 -268.885416)
		(mid 367.669957 -268.818096)
		(end 367.39576 -268.894052)
		(width 0.0889)
		(layer "B.Cu")
		(net "FM_S3M_CPU0_CPLD_CONFIG_N")
	)
	(arc
		(start 375.854214 -268.894052)
		(mid 375.667016 -268.944195)
		(end 375.479818 -268.894052)
		(width 0.0889)
		(layer "B.Cu")
		(net "FM_S3M_CPU0_CPLD_CONFIG_N")
	)
	(arc
		(start 378.299218 -268.894052)
		(mid 378.025019 -268.818217)
		(end 377.748546 -268.885416)
		(width 0.0889)
		(layer "B.Cu")
		(net "FM_S3M_CPU0_CPLD_CONFIG_N")
	)
	(arc
		(start 370.780564 -268.894052)
		(mid 370.497862 -268.818276)
		(end 370.21516 -268.894052)
		(width 0.0889)
		(layer "B.Cu")
		(net "FM_S3M_CPU0_CPLD_CONFIG_N")
	)
	(arc
		(start 376.794014 -268.894052)
		(mid 376.606816 -268.944195)
		(end 376.419618 -268.894052)
		(width 0.0889)
		(layer "B.Cu")
		(net "FM_S3M_CPU0_CPLD_CONFIG_N")
	)
	(arc
		(start 371.720618 -268.894052)
		(mid 371.443805 -268.818182)
		(end 371.165374 -268.887956)
		(width 0.0889)
		(layer "B.Cu")
		(net "FM_S3M_CPU0_CPLD_CONFIG_N")
	)
	(arc
		(start 372.095014 -268.894052)
		(mid 371.907816 -268.944195)
		(end 371.720618 -268.894052)
		(width 0.0889)
		(layer "B.Cu")
		(net "FM_S3M_CPU0_CPLD_CONFIG_N")
	)
	(arc
		(start 382.998218 -268.894052)
		(mid 382.724019 -268.818217)
		(end 382.447546 -268.885416)
		(width 0.0889)
		(layer "B.Cu")
		(net "FM_S3M_CPU0_CPLD_CONFIG_N")
	)
	(arc
		(start 368.33556 -268.894052)
		(mid 368.148362 -268.944195)
		(end 367.961164 -268.894052)
		(width 0.0889)
		(layer "B.Cu")
		(net "FM_S3M_CPU0_CPLD_CONFIG_N")
	)
	(arc
		(start 380.178818 -268.894052)
		(mid 379.904619 -268.818217)
		(end 379.628146 -268.885416)
		(width 0.0889)
		(layer "B.Cu")
		(net "FM_S3M_CPU0_CPLD_CONFIG_N")
	)
	(arc
		(start 371.15496 -268.894052)
		(mid 370.967762 -268.944195)
		(end 370.780564 -268.894052)
		(width 0.0889)
		(layer "B.Cu")
		(net "FM_S3M_CPU0_CPLD_CONFIG_N")
	)
	(arc
		(start 381.118618 -268.894052)
		(mid 380.835916 -268.818276)
		(end 380.553214 -268.894052)
		(width 0.0889)
		(layer "B.Cu")
		(net "FM_S3M_CPU0_CPLD_CONFIG_N")
	)
	(arc
		(start 369.83035 -268.887956)
		(mid 369.552172 -268.818233)
		(end 369.275614 -268.894052)
		(width 0.0889)
		(layer "B.Cu")
		(net "FM_S3M_CPU0_CPLD_CONFIG_N")
	)
	(arc
		(start 382.432814 -268.894052)
		(mid 382.245616 -268.944195)
		(end 382.058418 -268.894052)
		(width 0.0889)
		(layer "B.Cu")
		(net "FM_S3M_CPU0_CPLD_CONFIG_N")
	)
	(arc
		(start 376.419618 -268.894052)
		(mid 376.145419 -268.818217)
		(end 375.868946 -268.885416)
		(width 0.0889)
		(layer "B.Cu")
		(net "FM_S3M_CPU0_CPLD_CONFIG_N")
	)
	(arc
		(start 382.058418 -268.894052)
		(mid 381.784219 -268.818217)
		(end 381.507746 -268.885416)
		(width 0.0889)
		(layer "B.Cu")
		(net "FM_S3M_CPU0_CPLD_CONFIG_N")
	)
	(arc
		(start 374.914414 -268.894052)
		(mid 374.727216 -268.944195)
		(end 374.540018 -268.894052)
		(width 0.0889)
		(layer "B.Cu")
		(net "FM_S3M_CPU0_CPLD_CONFIG_N")
	)
	(arc
		(start 367.39576 -268.894052)
		(mid 367.208562 -268.944195)
		(end 367.021364 -268.894052)
		(width 0.0889)
		(layer "B.Cu")
		(net "FM_S3M_CPU0_CPLD_CONFIG_N")
	)
	(arc
		(start 380.553214 -268.894052)
		(mid 380.366016 -268.944195)
		(end 380.178818 -268.894052)
		(width 0.0889)
		(layer "B.Cu")
		(net "FM_S3M_CPU0_CPLD_CONFIG_N")
	)
	(arc
		(start 377.733814 -268.894052)
		(mid 377.546616 -268.944195)
		(end 377.359418 -268.894052)
		(width 0.0889)
		(layer "B.Cu")
		(net "FM_S3M_CPU0_CPLD_CONFIG_N")
	)
	(arc
		(start 373.600218 -268.894052)
		(mid 373.326019 -268.818217)
		(end 373.049546 -268.885416)
		(width 0.0889)
		(layer "B.Cu")
		(net "FM_S3M_CPU0_CPLD_CONFIG_N")
	)
	(arc
		(start 379.239018 -268.894052)
		(mid 378.964819 -268.818217)
		(end 378.688346 -268.885416)
		(width 0.0889)
		(layer "B.Cu")
		(net "FM_S3M_CPU0_CPLD_CONFIG_N")
	)
	(arc
		(start 373.034814 -268.894052)
		(mid 372.847616 -268.944195)
		(end 372.660418 -268.894052)
		(width 0.0889)
		(layer "B.Cu")
		(net "FM_S3M_CPU0_CPLD_CONFIG_N")
	)
	(arc
		(start 366.071404 -268.887956)
		(mid 365.825698 -268.818702)
		(end 365.57458 -268.864588)
		(width 0.0889)
		(layer "B.Cu")
		(net "FM_S3M_CPU0_CPLD_CONFIG_N")
	)
	(arc
		(start 367.01095 -268.887956)
		(mid 366.732772 -268.818233)
		(end 366.456214 -268.894052)
		(width 0.0889)
		(layer "B.Cu")
		(net "FM_S3M_CPU0_CPLD_CONFIG_N")
	)
	(arc
		(start 372.660418 -268.894052)
		(mid 372.386219 -268.818217)
		(end 372.109746 -268.885416)
		(width 0.0889)
		(layer "B.Cu")
		(net "FM_S3M_CPU0_CPLD_CONFIG_N")
	)
	(arc
		(start 384.194558 -268.93901)
		(mid 384.077735 -268.942531)
		(end 383.96545 -268.910054)
		(width 0.0889)
		(layer "B.Cu")
		(net "FM_S3M_CPU0_CPLD_CONFIG_N")
	)
	(arc
		(start 374.540018 -268.894052)
		(mid 374.265819 -268.818217)
		(end 373.989346 -268.885416)
		(width 0.0889)
		(layer "B.Cu")
		(net "FM_S3M_CPU0_CPLD_CONFIG_N")
	)
	(arc
		(start 373.974614 -268.894052)
		(mid 373.787416 -268.944195)
		(end 373.600218 -268.894052)
		(width 0.0889)
		(layer "B.Cu")
		(net "FM_S3M_CPU0_CPLD_CONFIG_N")
	)
	(arc
		(start 377.359418 -268.894052)
		(mid 377.085219 -268.818217)
		(end 376.808746 -268.885416)
		(width 0.0889)
		(layer "B.Cu")
		(net "FM_S3M_CPU0_CPLD_CONFIG_N")
	)
	(arc
		(start 379.613414 -268.894052)
		(mid 379.426216 -268.944195)
		(end 379.239018 -268.894052)
		(width 0.0889)
		(layer "B.Cu")
		(net "FM_S3M_CPU0_CPLD_CONFIG_N")
	)
	(arc
		(start 378.673614 -268.894052)
		(mid 378.486416 -268.944195)
		(end 378.299218 -268.894052)
		(width 0.0889)
		(layer "B.Cu")
		(net "FM_S3M_CPU0_CPLD_CONFIG_N")
	)
	(arc
		(start 368.901218 -268.894052)
		(mid 368.624405 -268.818182)
		(end 368.345974 -268.887956)
		(width 0.0889)
		(layer "B.Cu")
		(net "FM_S3M_CPU0_CPLD_CONFIG_N")
	)
	(arc
		(start 383.372614 -268.894052)
		(mid 383.185416 -268.944195)
		(end 382.998218 -268.894052)
		(width 0.0889)
		(layer "B.Cu")
		(net "FM_S3M_CPU0_CPLD_CONFIG_N")
	)
	(arc
		(start 370.21516 -268.894052)
		(mid 370.027962 -268.944195)
		(end 369.840764 -268.894052)
		(width 0.0889)
		(layer "B.Cu")
		(net "FM_S3M_CPU0_CPLD_CONFIG_N")
	)
	(arc
		(start 366.456214 -268.894052)
		(mid 366.269016 -268.944195)
		(end 366.081818 -268.894052)
		(width 0.0889)
		(layer "B.Cu")
		(net "FM_S3M_CPU0_CPLD_CONFIG_N")
	)
	(arc
		(start 369.275614 -268.894052)
		(mid 369.088416 -268.944195)
		(end 368.901218 -268.894052)
		(width 0.0889)
		(layer "B.Cu")
		(net "FM_S3M_CPU0_CPLD_CONFIG_N")
	)
	(segment
		(start 184.555638 -110.575344)
		(end 184.955688 -110.175294)
		(width 0.12954)
		(layer "F.Cu")
		(net "FM_RST_PERST_BIT2")
	)
	(via
		(at 184.955688 -110.175294)
		(size 0.4572)
		(drill 0.254)
		(layers "F.Cu" "B.Cu")
		(net "FM_RST_PERST_BIT2")
	)
	(via
		(at 190.08852 -108.979208)
		(size 0.6604)
		(drill 0.3302)
		(layers "F.Cu" "B.Cu")
		(net "FM_RST_PERST_BIT2")
	)
	(segment
		(start 184.68594 -108.979208)
		(end 190.08852 -108.979208)
		(width 0.12954)
		(layer "B.Cu")
		(net "FM_RST_PERST_BIT2")
	)
	(segment
		(start 193.20383 -104.955848)
		(end 193.20383 -106.225848)
		(width 0.12954)
		(layer "B.Cu")
		(net "FM_RST_PERST_BIT2")
	)
	(segment
		(start 184.55386 -109.773466)
		(end 184.55386 -109.111288)
		(width 0.12954)
		(layer "B.Cu")
		(net "FM_RST_PERST_BIT2")
	)
	(segment
		(start 184.55386 -109.111288)
		(end 184.68594 -108.979208)
		(width 0.12954)
		(layer "B.Cu")
		(net "FM_RST_PERST_BIT2")
	)
	(segment
		(start 192.84188 -106.225848)
		(end 193.20383 -106.225848)
		(width 0.12954)
		(layer "B.Cu")
		(net "FM_RST_PERST_BIT2")
	)
	(segment
		(start 190.08852 -108.979208)
		(end 192.84188 -106.225848)
		(width 0.12954)
		(layer "B.Cu")
		(net "FM_RST_PERST_BIT2")
	)
	(segment
		(start 184.955688 -110.175294)
		(end 184.55386 -109.773466)
		(width 0.12954)
		(layer "B.Cu")
		(net "FM_RST_PERST_BIT2")
	)
	(segment
		(start 180.555646 -117.775482)
		(end 180.955696 -118.175532)
		(width 0.12954)
		(layer "F.Cu")
		(net "FM_RST_PERST_BIT1")
	)
	(segment
		(start 190.80988 -133.295898)
		(end 190.80988 -132.679948)
		(width 0.12954)
		(layer "F.Cu")
		(net "FM_RST_PERST_BIT1")
	)
	(via
		(at 180.955696 -118.175532)
		(size 0.4572)
		(drill 0.254)
		(layers "F.Cu" "B.Cu")
		(net "FM_RST_PERST_BIT1")
	)
	(via
		(at 190.80988 -132.679948)
		(size 0.508)
		(drill 0.254)
		(layers "F.Cu" "B.Cu")
		(net "FM_RST_PERST_BIT1")
	)
	(segment
		(start 182.1561 -117.978428)
		(end 181.95544 -117.777768)
		(width 0.12954)
		(layer "B.Cu")
		(net "FM_RST_PERST_BIT1")
	)
	(segment
		(start 190.377064 -129.866898)
		(end 190.80988 -129.866898)
		(width 0.12954)
		(layer "B.Cu")
		(net "FM_RST_PERST_BIT1")
	)
	(segment
		(start 190.80988 -132.679948)
		(end 190.06058 -131.930648)
		(width 0.12954)
		(layer "B.Cu")
		(net "FM_RST_PERST_BIT1")
	)
	(segment
		(start 183.58231 -124.238258)
		(end 183.58231 -122.513344)
		(width 0.12954)
		(layer "B.Cu")
		(net "FM_RST_PERST_BIT1")
	)
	(segment
		(start 182.95366 -118.748048)
		(end 182.78094 -118.575328)
		(width 0.12954)
		(layer "B.Cu")
		(net "FM_RST_PERST_BIT1")
	)
	(segment
		(start 190.80988 -132.679948)
		(end 190.07328 -133.416548)
		(width 0.12954)
		(layer "B.Cu")
		(net "FM_RST_PERST_BIT1")
	)
	(segment
		(start 183.58231 -122.513344)
		(end 182.95366 -121.884694)
		(width 0.12954)
		(layer "B.Cu")
		(net "FM_RST_PERST_BIT1")
	)
	(segment
		(start 181.120796 -118.175532)
		(end 180.955696 -118.175532)
		(width 0.12954)
		(layer "B.Cu")
		(net "FM_RST_PERST_BIT1")
	)
	(segment
		(start 185.97626 -132.748528)
		(end 185.97626 -126.632208)
		(width 0.12954)
		(layer "B.Cu")
		(net "FM_RST_PERST_BIT1")
	)
	(segment
		(start 185.97626 -126.632208)
		(end 183.58231 -124.238258)
		(width 0.12954)
		(layer "B.Cu")
		(net "FM_RST_PERST_BIT1")
	)
	(segment
		(start 182.95366 -121.884694)
		(end 182.95366 -118.748048)
		(width 0.12954)
		(layer "B.Cu")
		(net "FM_RST_PERST_BIT1")
	)
	(segment
		(start 181.95544 -117.777768)
		(end 181.51856 -117.777768)
		(width 0.12954)
		(layer "B.Cu")
		(net "FM_RST_PERST_BIT1")
	)
	(segment
		(start 182.1561 -118.392448)
		(end 182.1561 -117.978428)
		(width 0.12954)
		(layer "B.Cu")
		(net "FM_RST_PERST_BIT1")
	)
	(segment
		(start 190.07328 -133.416548)
		(end 186.64428 -133.416548)
		(width 0.12954)
		(layer "B.Cu")
		(net "FM_RST_PERST_BIT1")
	)
	(segment
		(start 190.06058 -131.930648)
		(end 190.06058 -130.183382)
		(width 0.12954)
		(layer "B.Cu")
		(net "FM_RST_PERST_BIT1")
	)
	(segment
		(start 182.33898 -118.575328)
		(end 182.1561 -118.392448)
		(width 0.12954)
		(layer "B.Cu")
		(net "FM_RST_PERST_BIT1")
	)
	(segment
		(start 182.78094 -118.575328)
		(end 182.33898 -118.575328)
		(width 0.12954)
		(layer "B.Cu")
		(net "FM_RST_PERST_BIT1")
	)
	(segment
		(start 190.06058 -130.183382)
		(end 190.377064 -129.866898)
		(width 0.12954)
		(layer "B.Cu")
		(net "FM_RST_PERST_BIT1")
	)
	(segment
		(start 181.51856 -117.777768)
		(end 181.120796 -118.175532)
		(width 0.12954)
		(layer "B.Cu")
		(net "FM_RST_PERST_BIT1")
	)
	(segment
		(start 186.64428 -133.416548)
		(end 185.97626 -132.748528)
		(width 0.12954)
		(layer "B.Cu")
		(net "FM_RST_PERST_BIT1")
	)
	(segment
		(start 180.555646 -118.575328)
		(end 180.955696 -118.975378)
		(width 0.12954)
		(layer "F.Cu")
		(net "FM_RST_PERST_BIT0")
	)
	(segment
		(start 189.28588 -133.295898)
		(end 189.28588 -132.679948)
		(width 0.12954)
		(layer "F.Cu")
		(net "FM_RST_PERST_BIT0")
	)
	(via
		(at 180.955696 -118.975378)
		(size 0.4572)
		(drill 0.254)
		(layers "F.Cu" "B.Cu")
		(net "FM_RST_PERST_BIT0")
	)
	(via
		(at 189.28588 -132.679948)
		(size 0.508)
		(drill 0.254)
		(layers "F.Cu" "B.Cu")
		(net "FM_RST_PERST_BIT0")
	)
	(segment
		(start 188.858144 -129.866898)
		(end 189.28588 -129.866898)
		(width 0.12954)
		(layer "B.Cu")
		(net "FM_RST_PERST_BIT0")
	)
	(segment
		(start 189.28588 -132.679948)
		(end 188.74994 -132.144008)
		(width 0.12954)
		(layer "B.Cu")
		(net "FM_RST_PERST_BIT0")
	)
	(segment
		(start 188.74994 -132.144008)
		(end 188.74994 -129.975102)
		(width 0.12954)
		(layer "B.Cu")
		(net "FM_RST_PERST_BIT0")
	)
	(segment
		(start 188.74994 -129.975102)
		(end 188.858144 -129.866898)
		(width 0.12954)
		(layer "B.Cu")
		(net "FM_RST_PERST_BIT0")
	)
	(segment
		(start 182.1561 -119.964708)
		(end 182.1561 -119.568468)
		(width 0.127)
		(layer "In2.Cu")
		(net "FM_RST_PERST_BIT0")
	)
	(segment
		(start 181.350666 -119.370348)
		(end 180.955696 -118.975378)
		(width 0.127)
		(layer "In2.Cu")
		(net "FM_RST_PERST_BIT0")
	)
	(segment
		(start 188.1632 -131.557268)
		(end 188.1632 -126.896368)
		(width 0.127)
		(layer "In2.Cu")
		(net "FM_RST_PERST_BIT0")
	)
	(segment
		(start 188.1632 -126.896368)
		(end 182.96128 -121.694448)
		(width 0.127)
		(layer "In2.Cu")
		(net "FM_RST_PERST_BIT0")
	)
	(segment
		(start 182.1561 -119.568468)
		(end 181.95798 -119.370348)
		(width 0.127)
		(layer "In2.Cu")
		(net "FM_RST_PERST_BIT0")
	)
	(segment
		(start 182.74792 -120.172988)
		(end 182.36438 -120.172988)
		(width 0.127)
		(layer "In2.Cu")
		(net "FM_RST_PERST_BIT0")
	)
	(segment
		(start 181.95798 -119.370348)
		(end 181.350666 -119.370348)
		(width 0.127)
		(layer "In2.Cu")
		(net "FM_RST_PERST_BIT0")
	)
	(segment
		(start 182.36438 -120.172988)
		(end 182.1561 -119.964708)
		(width 0.127)
		(layer "In2.Cu")
		(net "FM_RST_PERST_BIT0")
	)
	(segment
		(start 182.96128 -120.386348)
		(end 182.74792 -120.172988)
		(width 0.127)
		(layer "In2.Cu")
		(net "FM_RST_PERST_BIT0")
	)
	(segment
		(start 182.96128 -121.694448)
		(end 182.96128 -120.386348)
		(width 0.127)
		(layer "In2.Cu")
		(net "FM_RST_PERST_BIT0")
	)
	(segment
		(start 189.28588 -132.679948)
		(end 188.1632 -131.557268)
		(width 0.127)
		(layer "In2.Cu")
		(net "FM_RST_PERST_BIT0")
	)
	(segment
		(start 90.49893 -55.717948)
		(end 90.49893 -56.352948)
		(width 0.12954)
		(layer "F.Cu")
		(net "FM_REMOTE_DEBUG_DET_R")
	)
	(segment
		(start 90.49893 -56.352948)
		(end 90.49893 -57.368948)
		(width 0.12954)
		(layer "F.Cu")
		(net "FM_REMOTE_DEBUG_DET_R")
	)
	(segment
		(start 90.49893 -57.368948)
		(end 90.69197 -57.175908)
		(width 0.12954)
		(layer "F.Cu")
		(net "FM_REMOTE_DEBUG_DET_R")
	)
	(segment
		(start 90.69197 -57.175908)
		(end 92.173806 -57.175908)
		(width 0.12954)
		(layer "F.Cu")
		(net "FM_REMOTE_DEBUG_DET_R")
	)
	(via
		(at 199.53224 -106.147108)
		(size 0.508)
		(drill 0.254)
		(layers "F.Cu" "B.Cu")
		(net "FM_REMOTE_DEBUG_DET_R")
	)
	(via
		(at 90.49893 -55.717948)
		(size 0.508)
		(drill 0.254)
		(layers "F.Cu" "B.Cu")
		(net "FM_REMOTE_DEBUG_DET_R")
	)
	(via
		(at 140.564108 -58.748168)
		(size 0.508)
		(drill 0.254)
		(layers "F.Cu" "B.Cu")
		(net "FM_REMOTE_DEBUG_DET_R")
	)
	(segment
		(start 198.0311 -105.580688)
		(end 197.81393 -105.797858)
		(width 0.12954)
		(layer "B.Cu")
		(net "FM_REMOTE_DEBUG_DET_R")
	)
	(segment
		(start 197.81393 -105.797858)
		(end 197.81393 -106.225848)
		(width 0.12954)
		(layer "B.Cu")
		(net "FM_REMOTE_DEBUG_DET_R")
	)
	(segment
		(start 199.53224 -106.147108)
		(end 198.96582 -105.580688)
		(width 0.12954)
		(layer "B.Cu")
		(net "FM_REMOTE_DEBUG_DET_R")
	)
	(segment
		(start 198.96582 -105.580688)
		(end 198.0311 -105.580688)
		(width 0.12954)
		(layer "B.Cu")
		(net "FM_REMOTE_DEBUG_DET_R")
	)
	(segment
		(start 158.27629 -66.213228)
		(end 143.83131 -66.213228)
		(width 0.127)
		(layer "In4.Cu")
		(net "FM_REMOTE_DEBUG_DET_R")
	)
	(segment
		(start 199.34936 -104.504998)
		(end 199.3392 -104.494838)
		(width 0.127)
		(layer "In4.Cu")
		(net "FM_REMOTE_DEBUG_DET_R")
	)
	(segment
		(start 189.026546 -84.04479)
		(end 177.47234 -84.04479)
		(width 0.127)
		(layer "In4.Cu")
		(net "FM_REMOTE_DEBUG_DET_R")
	)
	(segment
		(start 199.34936 -105.964228)
		(end 199.34936 -104.504998)
		(width 0.127)
		(layer "In4.Cu")
		(net "FM_REMOTE_DEBUG_DET_R")
	)
	(segment
		(start 199.53224 -106.147108)
		(end 199.34936 -105.964228)
		(width 0.127)
		(layer "In4.Cu")
		(net "FM_REMOTE_DEBUG_DET_R")
	)
	(segment
		(start 197.44055 -102.595934)
		(end 197.44055 -100.228146)
		(width 0.127)
		(layer "In4.Cu")
		(net "FM_REMOTE_DEBUG_DET_R")
	)
	(segment
		(start 160.832038 -67.404488)
		(end 159.46755 -67.404488)
		(width 0.127)
		(layer "In4.Cu")
		(net "FM_REMOTE_DEBUG_DET_R")
	)
	(segment
		(start 140.564108 -62.946026)
		(end 140.564108 -58.748168)
		(width 0.127)
		(layer "In4.Cu")
		(net "FM_REMOTE_DEBUG_DET_R")
	)
	(segment
		(start 199.3392 -104.494838)
		(end 199.3392 -104.494584)
		(width 0.127)
		(layer "In4.Cu")
		(net "FM_REMOTE_DEBUG_DET_R")
	)
	(segment
		(start 159.46755 -67.404488)
		(end 158.27629 -66.213228)
		(width 0.127)
		(layer "In4.Cu")
		(net "FM_REMOTE_DEBUG_DET_R")
	)
	(segment
		(start 197.44055 -100.228146)
		(end 191.15786 -93.945456)
		(width 0.127)
		(layer "In4.Cu")
		(net "FM_REMOTE_DEBUG_DET_R")
	)
	(segment
		(start 199.3392 -104.494584)
		(end 197.44055 -102.595934)
		(width 0.127)
		(layer "In4.Cu")
		(net "FM_REMOTE_DEBUG_DET_R")
	)
	(segment
		(start 191.15786 -86.176104)
		(end 189.026546 -84.04479)
		(width 0.127)
		(layer "In4.Cu")
		(net "FM_REMOTE_DEBUG_DET_R")
	)
	(segment
		(start 177.47234 -84.04479)
		(end 160.832038 -67.404488)
		(width 0.127)
		(layer "In4.Cu")
		(net "FM_REMOTE_DEBUG_DET_R")
	)
	(segment
		(start 143.83131 -66.213228)
		(end 140.564108 -62.946026)
		(width 0.127)
		(layer "In4.Cu")
		(net "FM_REMOTE_DEBUG_DET_R")
	)
	(segment
		(start 191.15786 -93.945456)
		(end 191.15786 -86.176104)
		(width 0.127)
		(layer "In4.Cu")
		(net "FM_REMOTE_DEBUG_DET_R")
	)
	(segment
		(start 90.49893 -55.717948)
		(end 93.78315 -59.002168)
		(width 0.127)
		(layer "In6.Cu")
		(net "FM_REMOTE_DEBUG_DET_R")
	)
	(segment
		(start 109.9566 -59.002168)
		(end 124.42698 -59.002168)
		(width 0.127)
		(layer "In6.Cu")
		(net "FM_REMOTE_DEBUG_DET_R")
	)
	(segment
		(start 93.78315 -59.002168)
		(end 102.9208 -59.002168)
		(width 0.127)
		(layer "In6.Cu")
		(net "FM_REMOTE_DEBUG_DET_R")
	)
	(segment
		(start 103.48722 -58.435748)
		(end 109.39018 -58.435748)
		(width 0.127)
		(layer "In6.Cu")
		(net "FM_REMOTE_DEBUG_DET_R")
	)
	(segment
		(start 109.39018 -58.435748)
		(end 109.9566 -59.002168)
		(width 0.127)
		(layer "In6.Cu")
		(net "FM_REMOTE_DEBUG_DET_R")
	)
	(segment
		(start 140.073888 -58.257948)
		(end 140.564108 -58.748168)
		(width 0.127)
		(layer "In6.Cu")
		(net "FM_REMOTE_DEBUG_DET_R")
	)
	(segment
		(start 124.42698 -59.002168)
		(end 125.1712 -58.257948)
		(width 0.127)
		(layer "In6.Cu")
		(net "FM_REMOTE_DEBUG_DET_R")
	)
	(segment
		(start 125.1712 -58.257948)
		(end 140.073888 -58.257948)
		(width 0.127)
		(layer "In6.Cu")
		(net "FM_REMOTE_DEBUG_DET_R")
	)
	(segment
		(start 102.9208 -59.002168)
		(end 103.48722 -58.435748)
		(width 0.127)
		(layer "In6.Cu")
		(net "FM_REMOTE_DEBUG_DET_R")
	)
	(segment
		(start 183.755538 -110.575344)
		(end 184.155588 -110.175294)
		(width 0.12954)
		(layer "F.Cu")
		(net "FM_REMOTE_DEBUG_DET")
	)
	(via
		(at 188.5823 -109.593888)
		(size 0.6604)
		(drill 0.3302)
		(layers "F.Cu" "B.Cu")
		(net "FM_REMOTE_DEBUG_DET")
	)
	(via
		(at 184.155588 -110.175294)
		(size 0.4572)
		(drill 0.254)
		(layers "F.Cu" "B.Cu")
		(net "FM_REMOTE_DEBUG_DET")
	)
	(segment
		(start 193.1162 -106.815128)
		(end 196.710046 -106.815128)
		(width 0.12954)
		(layer "B.Cu")
		(net "FM_REMOTE_DEBUG_DET")
	)
	(segment
		(start 187.72886 -109.593888)
		(end 188.5823 -109.593888)
		(width 0.12954)
		(layer "B.Cu")
		(net "FM_REMOTE_DEBUG_DET")
	)
	(segment
		(start 184.557162 -110.576868)
		(end 186.74588 -110.576868)
		(width 0.12954)
		(layer "B.Cu")
		(net "FM_REMOTE_DEBUG_DET")
	)
	(segment
		(start 190.33744 -109.593888)
		(end 193.1162 -106.815128)
		(width 0.12954)
		(layer "B.Cu")
		(net "FM_REMOTE_DEBUG_DET")
	)
	(segment
		(start 197.01383 -106.511344)
		(end 197.01383 -106.225848)
		(width 0.12954)
		(layer "B.Cu")
		(net "FM_REMOTE_DEBUG_DET")
	)
	(segment
		(start 184.155588 -110.175294)
		(end 184.557162 -110.576868)
		(width 0.12954)
		(layer "B.Cu")
		(net "FM_REMOTE_DEBUG_DET")
	)
	(segment
		(start 188.5823 -109.593888)
		(end 190.33744 -109.593888)
		(width 0.12954)
		(layer "B.Cu")
		(net "FM_REMOTE_DEBUG_DET")
	)
	(segment
		(start 186.74588 -110.576868)
		(end 187.72886 -109.593888)
		(width 0.12954)
		(layer "B.Cu")
		(net "FM_REMOTE_DEBUG_DET")
	)
	(segment
		(start 196.710046 -106.815128)
		(end 197.01383 -106.511344)
		(width 0.12954)
		(layer "B.Cu")
		(net "FM_REMOTE_DEBUG_DET")
	)
	(segment
		(start 201.621136 -170.500548)
		(end 181.592728 -170.500548)
		(width 0.12954)
		(layer "F.Cu")
		(net "FM_PVPP_HBM_CPU1_EN")
	)
	(segment
		(start 159.18688 -163.910772)
		(end 159.18688 -163.439348)
		(width 0.12954)
		(layer "F.Cu")
		(net "FM_PVPP_HBM_CPU1_EN")
	)
	(segment
		(start 124.314966 -357.260652)
		(end 123.961144 -357.260652)
		(width 0.12954)
		(layer "F.Cu")
		(net "FM_PVPP_HBM_CPU1_EN")
	)
	(segment
		(start 174.625 -135.600948)
		(end 174.625 -132.679948)
		(width 0.12954)
		(layer "F.Cu")
		(net "FM_PVPP_HBM_CPU1_EN")
	)
	(segment
		(start 172.92828 -125.364748)
		(end 172.92828 -123.002802)
		(width 0.12954)
		(layer "F.Cu")
		(net "FM_PVPP_HBM_CPU1_EN")
	)
	(segment
		(start 123.714256 -356.443534)
		(end 123.30557 -356.034848)
		(width 0.12954)
		(layer "F.Cu")
		(net "FM_PVPP_HBM_CPU1_EN")
	)
	(segment
		(start 181.592728 -170.500548)
		(end 180.30952 -169.21734)
		(width 0.12954)
		(layer "F.Cu")
		(net "FM_PVPP_HBM_CPU1_EN")
	)
	(segment
		(start 166.254684 -169.21734)
		(end 162.487102 -167.657018)
		(width 0.12954)
		(layer "F.Cu")
		(net "FM_PVPP_HBM_CPU1_EN")
	)
	(segment
		(start 123.961144 -357.260652)
		(end 123.714256 -357.013764)
		(width 0.12954)
		(layer "F.Cu")
		(net "FM_PVPP_HBM_CPU1_EN")
	)
	(segment
		(start 123.30557 -356.034848)
		(end 122.82424 -356.034848)
		(width 0.12954)
		(layer "F.Cu")
		(net "FM_PVPP_HBM_CPU1_EN")
	)
	(segment
		(start 174.625 -132.679948)
		(end 173.414944 -131.469892)
		(width 0.12954)
		(layer "F.Cu")
		(net "FM_PVPP_HBM_CPU1_EN")
	)
	(segment
		(start 123.714256 -357.013764)
		(end 123.714256 -356.443534)
		(width 0.12954)
		(layer "F.Cu")
		(net "FM_PVPP_HBM_CPU1_EN")
	)
	(segment
		(start 159.26308 -163.910772)
		(end 159.18688 -163.910772)
		(width 0.12954)
		(layer "F.Cu")
		(net "FM_PVPP_HBM_CPU1_EN")
	)
	(segment
		(start 160.036256 -165.206172)
		(end 160.036002 -165.206172)
		(width 0.12954)
		(layer "F.Cu")
		(net "FM_PVPP_HBM_CPU1_EN")
	)
	(segment
		(start 217.089736 -185.969148)
		(end 201.621136 -170.500548)
		(width 0.12954)
		(layer "F.Cu")
		(net "FM_PVPP_HBM_CPU1_EN")
	)
	(segment
		(start 159.26308 -164.432996)
		(end 159.26308 -163.910772)
		(width 0.12954)
		(layer "F.Cu")
		(net "FM_PVPP_HBM_CPU1_EN")
	)
	(segment
		(start 173.414944 -131.469892)
		(end 173.414944 -125.851412)
		(width 0.12954)
		(layer "F.Cu")
		(net "FM_PVPP_HBM_CPU1_EN")
	)
	(segment
		(start 162.487102 -167.657018)
		(end 160.036256 -165.206172)
		(width 0.12954)
		(layer "F.Cu")
		(net "FM_PVPP_HBM_CPU1_EN")
	)
	(segment
		(start 181.43728 -151.755348)
		(end 178.438048 -151.755348)
		(width 0.12954)
		(layer "F.Cu")
		(net "FM_PVPP_HBM_CPU1_EN")
	)
	(segment
		(start 180.30952 -169.21734)
		(end 166.254684 -169.21734)
		(width 0.12954)
		(layer "F.Cu")
		(net "FM_PVPP_HBM_CPU1_EN")
	)
	(segment
		(start 173.414944 -125.851412)
		(end 172.92828 -125.364748)
		(width 0.12954)
		(layer "F.Cu")
		(net "FM_PVPP_HBM_CPU1_EN")
	)
	(segment
		(start 219.43695 -187.375038)
		(end 218.03106 -185.969148)
		(width 0.12954)
		(layer "F.Cu")
		(net "FM_PVPP_HBM_CPU1_EN")
	)
	(segment
		(start 173.414944 -146.732244)
		(end 173.414944 -136.811004)
		(width 0.12954)
		(layer "F.Cu")
		(net "FM_PVPP_HBM_CPU1_EN")
	)
	(segment
		(start 172.92828 -123.002802)
		(end 174.155608 -121.775474)
		(width 0.12954)
		(layer "F.Cu")
		(net "FM_PVPP_HBM_CPU1_EN")
	)
	(segment
		(start 218.03106 -185.969148)
		(end 217.089736 -185.969148)
		(width 0.12954)
		(layer "F.Cu")
		(net "FM_PVPP_HBM_CPU1_EN")
	)
	(segment
		(start 160.036002 -165.206172)
		(end 159.26308 -164.432996)
		(width 0.12954)
		(layer "F.Cu")
		(net "FM_PVPP_HBM_CPU1_EN")
	)
	(segment
		(start 173.414944 -136.811004)
		(end 174.625 -135.600948)
		(width 0.12954)
		(layer "F.Cu")
		(net "FM_PVPP_HBM_CPU1_EN")
	)
	(segment
		(start 178.438048 -151.755348)
		(end 173.414944 -146.732244)
		(width 0.12954)
		(layer "F.Cu")
		(net "FM_PVPP_HBM_CPU1_EN")
	)
	(via
		(at 181.43728 -151.755348)
		(size 0.508)
		(drill 0.254)
		(layers "F.Cu" "B.Cu")
		(net "FM_PVPP_HBM_CPU1_EN")
	)
	(via
		(at 122.82424 -356.034848)
		(size 0.508)
		(drill 0.254)
		(layers "F.Cu" "B.Cu")
		(net "FM_PVPP_HBM_CPU1_EN")
	)
	(via
		(at 159.18688 -163.439348)
		(size 0.508)
		(drill 0.254)
		(layers "F.Cu" "B.Cu")
		(net "FM_PVPP_HBM_CPU1_EN")
	)
	(via
		(at 219.43695 -187.375038)
		(size 0.762)
		(drill 0.254)
		(layers "F.Cu" "B.Cu")
		(net "FM_PVPP_HBM_CPU1_EN")
	)
	(segment
		(start 220.764354 -189.334902)
		(end 219.43695 -188.007498)
		(width 0.12954)
		(layer "B.Cu")
		(net "FM_PVPP_HBM_CPU1_EN")
	)
	(segment
		(start 117.893338 -367.151666)
		(end 119.00154 -368.259868)
		(width 0.12954)
		(layer "B.Cu")
		(net "FM_PVPP_HBM_CPU1_EN")
	)
	(segment
		(start 202.088496 -342.381332)
		(end 209.02168 -335.448148)
		(width 0.12954)
		(layer "B.Cu")
		(net "FM_PVPP_HBM_CPU1_EN")
	)
	(segment
		(start 229.34168 -203.872592)
		(end 220.764354 -195.295266)
		(width 0.12954)
		(layer "B.Cu")
		(net "FM_PVPP_HBM_CPU1_EN")
	)
	(segment
		(start 122.557794 -353.916742)
		(end 122.2248 -353.583748)
		(width 0.12954)
		(layer "B.Cu")
		(net "FM_PVPP_HBM_CPU1_EN")
	)
	(segment
		(start 122.557794 -354.189538)
		(end 122.557794 -353.916742)
		(width 0.12954)
		(layer "B.Cu")
		(net "FM_PVPP_HBM_CPU1_EN")
	)
	(segment
		(start 175.343566 -382.35509)
		(end 202.088496 -355.61016)
		(width 0.12954)
		(layer "B.Cu")
		(net "FM_PVPP_HBM_CPU1_EN")
	)
	(segment
		(start 158.95828 -155.285948)
		(end 158.95828 -163.210748)
		(width 0.12954)
		(layer "B.Cu")
		(net "FM_PVPP_HBM_CPU1_EN")
	)
	(segment
		(start 120.7643 -353.583748)
		(end 119.988838 -354.35921)
		(width 0.12954)
		(layer "B.Cu")
		(net "FM_PVPP_HBM_CPU1_EN")
	)
	(segment
		(start 179.35448 -153.203148)
		(end 161.04108 -153.203148)
		(width 0.12954)
		(layer "B.Cu")
		(net "FM_PVPP_HBM_CPU1_EN")
	)
	(segment
		(start 218.80068 -335.448148)
		(end 221.23908 -333.009748)
		(width 0.12954)
		(layer "B.Cu")
		(net "FM_PVPP_HBM_CPU1_EN")
	)
	(segment
		(start 219.43695 -188.007498)
		(end 219.43695 -187.375038)
		(width 0.12954)
		(layer "B.Cu")
		(net "FM_PVPP_HBM_CPU1_EN")
	)
	(segment
		(start 122.658632 -356.200456)
		(end 122.173492 -356.200456)
		(width 0.12954)
		(layer "B.Cu")
		(net "FM_PVPP_HBM_CPU1_EN")
	)
	(segment
		(start 220.764354 -195.295266)
		(end 220.764354 -189.334902)
		(width 0.12954)
		(layer "B.Cu")
		(net "FM_PVPP_HBM_CPU1_EN")
	)
	(segment
		(start 209.02168 -335.448148)
		(end 218.80068 -335.448148)
		(width 0.12954)
		(layer "B.Cu")
		(net "FM_PVPP_HBM_CPU1_EN")
	)
	(segment
		(start 221.23908 -333.009748)
		(end 221.23908 -246.751348)
		(width 0.12954)
		(layer "B.Cu")
		(net "FM_PVPP_HBM_CPU1_EN")
	)
	(segment
		(start 180.80228 -151.755348)
		(end 179.35448 -153.203148)
		(width 0.12954)
		(layer "B.Cu")
		(net "FM_PVPP_HBM_CPU1_EN")
	)
	(segment
		(start 158.95828 -163.210748)
		(end 159.18688 -163.439348)
		(width 0.12954)
		(layer "B.Cu")
		(net "FM_PVPP_HBM_CPU1_EN")
	)
	(segment
		(start 122.173492 -355.202744)
		(end 122.182128 -355.194108)
		(width 0.12954)
		(layer "B.Cu")
		(net "FM_PVPP_HBM_CPU1_EN")
	)
	(segment
		(start 161.04108 -153.203148)
		(end 158.95828 -155.285948)
		(width 0.12954)
		(layer "B.Cu")
		(net "FM_PVPP_HBM_CPU1_EN")
	)
	(segment
		(start 221.23908 -246.751348)
		(end 229.34168 -238.648748)
		(width 0.12954)
		(layer "B.Cu")
		(net "FM_PVPP_HBM_CPU1_EN")
	)
	(segment
		(start 122.82424 -356.034848)
		(end 122.658632 -356.200456)
		(width 0.12954)
		(layer "B.Cu")
		(net "FM_PVPP_HBM_CPU1_EN")
	)
	(segment
		(start 119.988838 -355.527102)
		(end 117.893338 -357.622602)
		(width 0.12954)
		(layer "B.Cu")
		(net "FM_PVPP_HBM_CPU1_EN")
	)
	(segment
		(start 119.00154 -380.406402)
		(end 120.950228 -382.35509)
		(width 0.12954)
		(layer "B.Cu")
		(net "FM_PVPP_HBM_CPU1_EN")
	)
	(segment
		(start 122.173492 -356.200456)
		(end 122.173492 -355.202744)
		(width 0.12954)
		(layer "B.Cu")
		(net "FM_PVPP_HBM_CPU1_EN")
	)
	(segment
		(start 229.34168 -238.648748)
		(end 229.34168 -203.872592)
		(width 0.12954)
		(layer "B.Cu")
		(net "FM_PVPP_HBM_CPU1_EN")
	)
	(segment
		(start 181.43728 -151.755348)
		(end 180.80228 -151.755348)
		(width 0.12954)
		(layer "B.Cu")
		(net "FM_PVPP_HBM_CPU1_EN")
	)
	(segment
		(start 202.088496 -355.61016)
		(end 202.088496 -342.381332)
		(width 0.12954)
		(layer "B.Cu")
		(net "FM_PVPP_HBM_CPU1_EN")
	)
	(segment
		(start 120.950228 -382.35509)
		(end 175.343566 -382.35509)
		(width 0.12954)
		(layer "B.Cu")
		(net "FM_PVPP_HBM_CPU1_EN")
	)
	(segment
		(start 119.00154 -368.259868)
		(end 119.00154 -380.406402)
		(width 0.12954)
		(layer "B.Cu")
		(net "FM_PVPP_HBM_CPU1_EN")
	)
	(segment
		(start 117.893338 -357.622602)
		(end 117.893338 -367.151666)
		(width 0.12954)
		(layer "B.Cu")
		(net "FM_PVPP_HBM_CPU1_EN")
	)
	(segment
		(start 122.2248 -353.583748)
		(end 120.7643 -353.583748)
		(width 0.12954)
		(layer "B.Cu")
		(net "FM_PVPP_HBM_CPU1_EN")
	)
	(segment
		(start 122.557794 -354.189538)
		(end 122.182128 -354.565204)
		(width 0.12954)
		(layer "B.Cu")
		(net "FM_PVPP_HBM_CPU1_EN")
	)
	(segment
		(start 119.988838 -354.35921)
		(end 119.988838 -355.527102)
		(width 0.12954)
		(layer "B.Cu")
		(net "FM_PVPP_HBM_CPU1_EN")
	)
	(segment
		(start 122.182128 -354.565204)
		(end 122.182128 -355.194108)
		(width 0.12954)
		(layer "B.Cu")
		(net "FM_PVPP_HBM_CPU1_EN")
	)
	(segment
		(start 371.140228 -356.514146)
		(end 370.831872 -356.30231)
		(width 0.12954)
		(layer "F.Cu")
		(net "FM_PVPP_HBM_CPU0_EN")
	)
	(segment
		(start 174.955708 -122.524266)
		(end 174.955708 -121.775474)
		(width 0.12954)
		(layer "F.Cu")
		(net "FM_PVPP_HBM_CPU0_EN")
	)
	(segment
		(start 174.675038 -128.356106)
		(end 174.675038 -122.804936)
		(width 0.12954)
		(layer "F.Cu")
		(net "FM_PVPP_HBM_CPU0_EN")
	)
	(segment
		(start 371.886734 -357.260652)
		(end 371.140228 -356.514146)
		(width 0.12954)
		(layer "F.Cu")
		(net "FM_PVPP_HBM_CPU0_EN")
	)
	(segment
		(start 174.675038 -122.804936)
		(end 174.955708 -122.524266)
		(width 0.12954)
		(layer "F.Cu")
		(net "FM_PVPP_HBM_CPU0_EN")
	)
	(segment
		(start 174.93488 -128.615948)
		(end 174.675038 -128.356106)
		(width 0.12954)
		(layer "F.Cu")
		(net "FM_PVPP_HBM_CPU0_EN")
	)
	(segment
		(start 175.31588 -128.615948)
		(end 174.93488 -128.615948)
		(width 0.12954)
		(layer "F.Cu")
		(net "FM_PVPP_HBM_CPU0_EN")
	)
	(segment
		(start 372.25478 -357.260652)
		(end 371.886734 -357.260652)
		(width 0.12954)
		(layer "F.Cu")
		(net "FM_PVPP_HBM_CPU0_EN")
	)
	(via
		(at 370.831872 -356.30231)
		(size 0.508)
		(drill 0.254)
		(layers "F.Cu" "B.Cu")
		(net "FM_PVPP_HBM_CPU0_EN")
	)
	(via
		(at 242.212876 -200.019158)
		(size 0.508)
		(drill 0.254)
		(layers "F.Cu" "B.Cu")
		(net "FM_PVPP_HBM_CPU0_EN")
	)
	(via
		(at 346.67444 -369.613688)
		(size 0.508)
		(drill 0.254)
		(layers "F.Cu" "B.Cu")
		(net "FM_PVPP_HBM_CPU0_EN")
	)
	(via
		(at 210.74888 -125.694948)
		(size 0.508)
		(drill 0.254)
		(layers "F.Cu" "B.Cu")
		(net "FM_PVPP_HBM_CPU0_EN")
	)
	(via
		(at 175.31588 -128.615948)
		(size 0.508)
		(drill 0.254)
		(layers "F.Cu" "B.Cu")
		(net "FM_PVPP_HBM_CPU0_EN")
	)
	(via
		(at 304.430684 -386.127752)
		(size 0.508)
		(drill 0.254)
		(layers "F.Cu" "B.Cu")
		(net "FM_PVPP_HBM_CPU0_EN")
	)
	(segment
		(start 370.831872 -356.30231)
		(end 370.831872 -355.95941)
		(width 0.12954)
		(layer "B.Cu")
		(net "FM_PVPP_HBM_CPU0_EN")
	)
	(segment
		(start 370.831872 -355.95941)
		(end 370.695474 -355.823012)
		(width 0.12954)
		(layer "B.Cu")
		(net "FM_PVPP_HBM_CPU0_EN")
	)
	(segment
		(start 369.756436 -355.33838)
		(end 370.695474 -355.33838)
		(width 0.12954)
		(layer "B.Cu")
		(net "FM_PVPP_HBM_CPU0_EN")
	)
	(segment
		(start 370.695474 -355.33838)
		(end 371.665246 -355.33838)
		(width 0.12954)
		(layer "B.Cu")
		(net "FM_PVPP_HBM_CPU0_EN")
	)
	(segment
		(start 370.695474 -355.823012)
		(end 370.695474 -355.33838)
		(width 0.12954)
		(layer "B.Cu")
		(net "FM_PVPP_HBM_CPU0_EN")
	)
	(segment
		(start 367.709958 -362.10113)
		(end 367.316258 -361.70743)
		(width 0.127)
		(layer "In4.Cu")
		(net "FM_PVPP_HBM_CPU0_EN")
	)
	(segment
		(start 290.502848 -381.599948)
		(end 299.90288 -381.599948)
		(width 0.127)
		(layer "In4.Cu")
		(net "FM_PVPP_HBM_CPU0_EN")
	)
	(segment
		(start 282.10256 -373.19966)
		(end 290.502848 -381.599948)
		(width 0.127)
		(layer "In4.Cu")
		(net "FM_PVPP_HBM_CPU0_EN")
	)
	(segment
		(start 175.31588 -128.615948)
		(end 179.2478 -128.615948)
		(width 0.127)
		(layer "In4.Cu")
		(net "FM_PVPP_HBM_CPU0_EN")
	)
	(segment
		(start 299.90288 -381.599948)
		(end 304.430684 -386.127752)
		(width 0.127)
		(layer "In4.Cu")
		(net "FM_PVPP_HBM_CPU0_EN")
	)
	(segment
		(start 180.35778 -127.505968)
		(end 184.303416 -127.505968)
		(width 0.127)
		(layer "In4.Cu")
		(net "FM_PVPP_HBM_CPU0_EN")
	)
	(segment
		(start 365.405416 -370.881148)
		(end 367.709958 -368.576606)
		(width 0.127)
		(layer "In4.Cu")
		(net "FM_PVPP_HBM_CPU0_EN")
	)
	(segment
		(start 367.316258 -359.817924)
		(end 370.831872 -356.30231)
		(width 0.127)
		(layer "In4.Cu")
		(net "FM_PVPP_HBM_CPU0_EN")
	)
	(segment
		(start 367.316258 -361.70743)
		(end 367.316258 -359.817924)
		(width 0.127)
		(layer "In4.Cu")
		(net "FM_PVPP_HBM_CPU0_EN")
	)
	(segment
		(start 192.252092 -130.277108)
		(end 197.94728 -130.277108)
		(width 0.127)
		(layer "In4.Cu")
		(net "FM_PVPP_HBM_CPU0_EN")
	)
	(segment
		(start 184.819036 -126.990348)
		(end 188.965332 -126.990348)
		(width 0.127)
		(layer "In4.Cu")
		(net "FM_PVPP_HBM_CPU0_EN")
	)
	(segment
		(start 179.2478 -128.615948)
		(end 180.35778 -127.505968)
		(width 0.127)
		(layer "In4.Cu")
		(net "FM_PVPP_HBM_CPU0_EN")
	)
	(segment
		(start 282.10256 -357.338376)
		(end 282.10256 -373.19966)
		(width 0.127)
		(layer "In4.Cu")
		(net "FM_PVPP_HBM_CPU0_EN")
	)
	(segment
		(start 367.709958 -368.576606)
		(end 367.709958 -362.10113)
		(width 0.127)
		(layer "In4.Cu")
		(net "FM_PVPP_HBM_CPU0_EN")
	)
	(segment
		(start 197.94728 -130.277108)
		(end 200.54062 -127.683768)
		(width 0.127)
		(layer "In4.Cu")
		(net "FM_PVPP_HBM_CPU0_EN")
	)
	(segment
		(start 252.88748 -279.1206)
		(end 250.49988 -281.5082)
		(width 0.127)
		(layer "In4.Cu")
		(net "FM_PVPP_HBM_CPU0_EN")
	)
	(segment
		(start 252.88748 -210.693762)
		(end 252.88748 -279.1206)
		(width 0.127)
		(layer "In4.Cu")
		(net "FM_PVPP_HBM_CPU0_EN")
	)
	(segment
		(start 209.35188 -127.091948)
		(end 210.74888 -125.694948)
		(width 0.127)
		(layer "In4.Cu")
		(net "FM_PVPP_HBM_CPU0_EN")
	)
	(segment
		(start 250.49988 -281.5082)
		(end 250.49988 -325.735696)
		(width 0.127)
		(layer "In4.Cu")
		(net "FM_PVPP_HBM_CPU0_EN")
	)
	(segment
		(start 351.36836 -369.613688)
		(end 352.63582 -370.881148)
		(width 0.127)
		(layer "In4.Cu")
		(net "FM_PVPP_HBM_CPU0_EN")
	)
	(segment
		(start 242.212876 -200.019158)
		(end 252.88748 -210.693762)
		(width 0.127)
		(layer "In4.Cu")
		(net "FM_PVPP_HBM_CPU0_EN")
	)
	(segment
		(start 352.63582 -370.881148)
		(end 365.405416 -370.881148)
		(width 0.127)
		(layer "In4.Cu")
		(net "FM_PVPP_HBM_CPU0_EN")
	)
	(segment
		(start 250.49988 -325.735696)
		(end 282.10256 -357.338376)
		(width 0.127)
		(layer "In4.Cu")
		(net "FM_PVPP_HBM_CPU0_EN")
	)
	(segment
		(start 200.54062 -127.683768)
		(end 206.93126 -127.683768)
		(width 0.127)
		(layer "In4.Cu")
		(net "FM_PVPP_HBM_CPU0_EN")
	)
	(segment
		(start 346.67444 -369.613688)
		(end 351.36836 -369.613688)
		(width 0.127)
		(layer "In4.Cu")
		(net "FM_PVPP_HBM_CPU0_EN")
	)
	(segment
		(start 207.52308 -127.091948)
		(end 209.35188 -127.091948)
		(width 0.127)
		(layer "In4.Cu")
		(net "FM_PVPP_HBM_CPU0_EN")
	)
	(segment
		(start 184.303416 -127.505968)
		(end 184.819036 -126.990348)
		(width 0.127)
		(layer "In4.Cu")
		(net "FM_PVPP_HBM_CPU0_EN")
	)
	(segment
		(start 206.93126 -127.683768)
		(end 207.52308 -127.091948)
		(width 0.127)
		(layer "In4.Cu")
		(net "FM_PVPP_HBM_CPU0_EN")
	)
	(segment
		(start 188.965332 -126.990348)
		(end 192.252092 -130.277108)
		(width 0.127)
		(layer "In4.Cu")
		(net "FM_PVPP_HBM_CPU0_EN")
	)
	(segment
		(start 346.67444 -369.613688)
		(end 343.305384 -372.982744)
		(width 0.127)
		(layer "In6.Cu")
		(net "FM_PVPP_HBM_CPU0_EN")
	)
	(segment
		(start 343.305384 -372.982744)
		(end 330.598272 -372.982744)
		(width 0.127)
		(layer "In6.Cu")
		(net "FM_PVPP_HBM_CPU0_EN")
	)
	(segment
		(start 330.598272 -372.982744)
		(end 317.453264 -386.127752)
		(width 0.127)
		(layer "In6.Cu")
		(net "FM_PVPP_HBM_CPU0_EN")
	)
	(segment
		(start 317.453264 -386.127752)
		(end 304.430684 -386.127752)
		(width 0.127)
		(layer "In6.Cu")
		(net "FM_PVPP_HBM_CPU0_EN")
	)
	(segment
		(start 212.02396 -133.05536)
		(end 210.52028 -131.55168)
		(width 0.127)
		(layer "In11.Cu")
		(net "FM_PVPP_HBM_CPU0_EN")
	)
	(segment
		(start 210.11388 -128.107948)
		(end 210.11388 -126.329948)
		(width 0.127)
		(layer "In11.Cu")
		(net "FM_PVPP_HBM_CPU0_EN")
	)
	(segment
		(start 221.005146 -146.073876)
		(end 212.02396 -137.09269)
		(width 0.127)
		(layer "In11.Cu")
		(net "FM_PVPP_HBM_CPU0_EN")
	)
	(segment
		(start 212.02396 -137.09269)
		(end 212.02396 -133.05536)
		(width 0.127)
		(layer "In11.Cu")
		(net "FM_PVPP_HBM_CPU0_EN")
	)
	(segment
		(start 242.212876 -200.019158)
		(end 242.212876 -199.788526)
		(width 0.127)
		(layer "In11.Cu")
		(net "FM_PVPP_HBM_CPU0_EN")
	)
	(segment
		(start 243.79428 -198.207122)
		(end 243.79428 -180.669184)
		(width 0.127)
		(layer "In11.Cu")
		(net "FM_PVPP_HBM_CPU0_EN")
	)
	(segment
		(start 210.52028 -131.55168)
		(end 210.52028 -128.514348)
		(width 0.127)
		(layer "In11.Cu")
		(net "FM_PVPP_HBM_CPU0_EN")
	)
	(segment
		(start 242.212876 -199.788526)
		(end 243.79428 -198.207122)
		(width 0.127)
		(layer "In11.Cu")
		(net "FM_PVPP_HBM_CPU0_EN")
	)
	(segment
		(start 221.005146 -157.88005)
		(end 221.005146 -146.073876)
		(width 0.127)
		(layer "In11.Cu")
		(net "FM_PVPP_HBM_CPU0_EN")
	)
	(segment
		(start 210.11388 -126.329948)
		(end 210.74888 -125.694948)
		(width 0.127)
		(layer "In11.Cu")
		(net "FM_PVPP_HBM_CPU0_EN")
	)
	(segment
		(start 243.79428 -180.669184)
		(end 221.005146 -157.88005)
		(width 0.127)
		(layer "In11.Cu")
		(net "FM_PVPP_HBM_CPU0_EN")
	)
	(segment
		(start 210.52028 -128.514348)
		(end 210.11388 -128.107948)
		(width 0.127)
		(layer "In11.Cu")
		(net "FM_PVPP_HBM_CPU0_EN")
	)
	(segment
		(start 21.34489 -177.191416)
		(end 21.34489 -178.334416)
		(width 0.12954)
		(layer "F.Cu")
		(net "FM_PVNN_MAIN_CPU1_EN")
	)
	(segment
		(start 21.938742 -178.928268)
		(end 22.15515 -178.928268)
		(width 0.12954)
		(layer "F.Cu")
		(net "FM_PVNN_MAIN_CPU1_EN")
	)
	(segment
		(start 21.34489 -178.334416)
		(end 21.938742 -178.928268)
		(width 0.12954)
		(layer "F.Cu")
		(net "FM_PVNN_MAIN_CPU1_EN")
	)
	(segment
		(start 173.355762 -120.975374)
		(end 172.955712 -121.375424)
		(width 0.12954)
		(layer "F.Cu")
		(net "FM_PVNN_MAIN_CPU1_EN")
	)
	(via
		(at 172.955712 -121.375424)
		(size 0.4572)
		(drill 0.254)
		(layers "F.Cu" "B.Cu")
		(net "FM_PVNN_MAIN_CPU1_EN")
	)
	(via
		(at 21.34489 -177.191416)
		(size 0.508)
		(drill 0.254)
		(layers "F.Cu" "B.Cu")
		(net "FM_PVNN_MAIN_CPU1_EN")
	)
	(via
		(at 149.91334 -122.969528)
		(size 0.508)
		(drill 0.254)
		(layers "F.Cu" "B.Cu")
		(net "FM_PVNN_MAIN_CPU1_EN")
	)
	(segment
		(start 21.34489 -177.191416)
		(end 21.34489 -176.163224)
		(width 0.12954)
		(layer "B.Cu")
		(net "FM_PVNN_MAIN_CPU1_EN")
	)
	(segment
		(start 19.588734 -176.023524)
		(end 18.620994 -176.023524)
		(width 0.12954)
		(layer "B.Cu")
		(net "FM_PVNN_MAIN_CPU1_EN")
	)
	(segment
		(start 20.566634 -176.023524)
		(end 19.588734 -176.023524)
		(width 0.12954)
		(layer "B.Cu")
		(net "FM_PVNN_MAIN_CPU1_EN")
	)
	(segment
		(start 21.20519 -176.023524)
		(end 20.566634 -176.023524)
		(width 0.12954)
		(layer "B.Cu")
		(net "FM_PVNN_MAIN_CPU1_EN")
	)
	(segment
		(start 21.34489 -176.163224)
		(end 21.20519 -176.023524)
		(width 0.12954)
		(layer "B.Cu")
		(net "FM_PVNN_MAIN_CPU1_EN")
	)
	(segment
		(start 18.620994 -176.023524)
		(end 18.613374 -176.031144)
		(width 0.12954)
		(layer "B.Cu")
		(net "FM_PVNN_MAIN_CPU1_EN")
	)
	(segment
		(start 170.68038 -121.58726)
		(end 169.16908 -121.58726)
		(width 0.127)
		(layer "In6.Cu")
		(net "FM_PVNN_MAIN_CPU1_EN")
	)
	(segment
		(start 169.16908 -121.58726)
		(end 165.79342 -124.96292)
		(width 0.127)
		(layer "In6.Cu")
		(net "FM_PVNN_MAIN_CPU1_EN")
	)
	(segment
		(start 172.57776 -121.93016)
		(end 171.02328 -121.93016)
		(width 0.127)
		(layer "In6.Cu")
		(net "FM_PVNN_MAIN_CPU1_EN")
	)
	(segment
		(start 165.79342 -124.96292)
		(end 150.92172 -124.96292)
		(width 0.127)
		(layer "In6.Cu")
		(net "FM_PVNN_MAIN_CPU1_EN")
	)
	(segment
		(start 149.91334 -123.95454)
		(end 149.91334 -122.969528)
		(width 0.127)
		(layer "In6.Cu")
		(net "FM_PVNN_MAIN_CPU1_EN")
	)
	(segment
		(start 150.92172 -124.96292)
		(end 149.91334 -123.95454)
		(width 0.127)
		(layer "In6.Cu")
		(net "FM_PVNN_MAIN_CPU1_EN")
	)
	(segment
		(start 172.955712 -121.375424)
		(end 172.955712 -121.552208)
		(width 0.127)
		(layer "In6.Cu")
		(net "FM_PVNN_MAIN_CPU1_EN")
	)
	(segment
		(start 172.955712 -121.552208)
		(end 172.57776 -121.93016)
		(width 0.127)
		(layer "In6.Cu")
		(net "FM_PVNN_MAIN_CPU1_EN")
	)
	(segment
		(start 171.02328 -121.93016)
		(end 170.68038 -121.58726)
		(width 0.127)
		(layer "In6.Cu")
		(net "FM_PVNN_MAIN_CPU1_EN")
	)
	(segment
		(start 32.45485 -171.928028)
		(end 22.67712 -171.928028)
		(width 0.127)
		(layer "In13.Cu")
		(net "FM_PVNN_MAIN_CPU1_EN")
	)
	(segment
		(start 106.26344 -121.163842)
		(end 105.39476 -121.163842)
		(width 0.127)
		(layer "In13.Cu")
		(net "FM_PVNN_MAIN_CPU1_EN")
	)
	(segment
		(start 131.756912 -117.266212)
		(end 110.16107 -117.266212)
		(width 0.127)
		(layer "In13.Cu")
		(net "FM_PVNN_MAIN_CPU1_EN")
	)
	(segment
		(start 20.9931 -135.063738)
		(end 36.54806 -150.618698)
		(width 0.127)
		(layer "In13.Cu")
		(net "FM_PVNN_MAIN_CPU1_EN")
	)
	(segment
		(start 20.9931 -125.255782)
		(end 20.9931 -135.063738)
		(width 0.127)
		(layer "In13.Cu")
		(net "FM_PVNN_MAIN_CPU1_EN")
	)
	(segment
		(start 35.179 -158.82239)
		(end 35.179 -169.203878)
		(width 0.127)
		(layer "In13.Cu")
		(net "FM_PVNN_MAIN_CPU1_EN")
	)
	(segment
		(start 22.67712 -171.928028)
		(end 21.34489 -173.260258)
		(width 0.127)
		(layer "In13.Cu")
		(net "FM_PVNN_MAIN_CPU1_EN")
	)
	(segment
		(start 104.780334 -121.778268)
		(end 48.76546 -121.778268)
		(width 0.127)
		(layer "In13.Cu")
		(net "FM_PVNN_MAIN_CPU1_EN")
	)
	(segment
		(start 36.54806 -150.618698)
		(end 36.54806 -157.45333)
		(width 0.127)
		(layer "In13.Cu")
		(net "FM_PVNN_MAIN_CPU1_EN")
	)
	(segment
		(start 47.79772 -120.810528)
		(end 25.438354 -120.810528)
		(width 0.127)
		(layer "In13.Cu")
		(net "FM_PVNN_MAIN_CPU1_EN")
	)
	(segment
		(start 48.76546 -121.778268)
		(end 47.79772 -120.810528)
		(width 0.127)
		(layer "In13.Cu")
		(net "FM_PVNN_MAIN_CPU1_EN")
	)
	(segment
		(start 110.16107 -117.266212)
		(end 106.26344 -121.163842)
		(width 0.127)
		(layer "In13.Cu")
		(net "FM_PVNN_MAIN_CPU1_EN")
	)
	(segment
		(start 21.34489 -173.260258)
		(end 21.34489 -177.191416)
		(width 0.127)
		(layer "In13.Cu")
		(net "FM_PVNN_MAIN_CPU1_EN")
	)
	(segment
		(start 144.69872 -122.969528)
		(end 139.91082 -118.181628)
		(width 0.127)
		(layer "In13.Cu")
		(net "FM_PVNN_MAIN_CPU1_EN")
	)
	(segment
		(start 36.54806 -157.45333)
		(end 35.179 -158.82239)
		(width 0.127)
		(layer "In13.Cu")
		(net "FM_PVNN_MAIN_CPU1_EN")
	)
	(segment
		(start 25.438354 -120.810528)
		(end 20.9931 -125.255782)
		(width 0.127)
		(layer "In13.Cu")
		(net "FM_PVNN_MAIN_CPU1_EN")
	)
	(segment
		(start 105.39476 -121.163842)
		(end 104.780334 -121.778268)
		(width 0.127)
		(layer "In13.Cu")
		(net "FM_PVNN_MAIN_CPU1_EN")
	)
	(segment
		(start 149.91334 -122.969528)
		(end 144.69872 -122.969528)
		(width 0.127)
		(layer "In13.Cu")
		(net "FM_PVNN_MAIN_CPU1_EN")
	)
	(segment
		(start 132.672328 -118.181628)
		(end 131.756912 -117.266212)
		(width 0.127)
		(layer "In13.Cu")
		(net "FM_PVNN_MAIN_CPU1_EN")
	)
	(segment
		(start 139.91082 -118.181628)
		(end 132.672328 -118.181628)
		(width 0.127)
		(layer "In13.Cu")
		(net "FM_PVNN_MAIN_CPU1_EN")
	)
	(segment
		(start 35.179 -169.203878)
		(end 32.45485 -171.928028)
		(width 0.127)
		(layer "In13.Cu")
		(net "FM_PVNN_MAIN_CPU1_EN")
	)
	(segment
		(start 172.49648 -125.567948)
		(end 172.130212 -125.934216)
		(width 0.12954)
		(layer "F.Cu")
		(net "FM_PVNN_MAIN_CPU0_EN")
	)
	(segment
		(start 172.130212 -132.182616)
		(end 171.75988 -132.552948)
		(width 0.12954)
		(layer "F.Cu")
		(net "FM_PVNN_MAIN_CPU0_EN")
	)
	(segment
		(start 172.130212 -125.934216)
		(end 172.130212 -132.182616)
		(width 0.12954)
		(layer "F.Cu")
		(net "FM_PVNN_MAIN_CPU0_EN")
	)
	(segment
		(start 431.304192 -179.65039)
		(end 431.706274 -180.052472)
		(width 0.12954)
		(layer "F.Cu")
		(net "FM_PVNN_MAIN_CPU0_EN")
	)
	(segment
		(start 172.49648 -122.89282)
		(end 172.49648 -125.567948)
		(width 0.12954)
		(layer "F.Cu")
		(net "FM_PVNN_MAIN_CPU0_EN")
	)
	(segment
		(start 431.706274 -180.052472)
		(end 431.890678 -180.052472)
		(width 0.12954)
		(layer "F.Cu")
		(net "FM_PVNN_MAIN_CPU0_EN")
	)
	(segment
		(start 173.355762 -121.775474)
		(end 173.355762 -122.033538)
		(width 0.12954)
		(layer "F.Cu")
		(net "FM_PVNN_MAIN_CPU0_EN")
	)
	(segment
		(start 173.355762 -122.033538)
		(end 172.49648 -122.89282)
		(width 0.12954)
		(layer "F.Cu")
		(net "FM_PVNN_MAIN_CPU0_EN")
	)
	(segment
		(start 431.890678 -180.052472)
		(end 431.966878 -179.976272)
		(width 0.12954)
		(layer "F.Cu")
		(net "FM_PVNN_MAIN_CPU0_EN")
	)
	(segment
		(start 431.304192 -179.238148)
		(end 431.304192 -179.65039)
		(width 0.12954)
		(layer "F.Cu")
		(net "FM_PVNN_MAIN_CPU0_EN")
	)
	(segment
		(start 171.75988 -132.552948)
		(end 171.50588 -132.552948)
		(width 0.12954)
		(layer "F.Cu")
		(net "FM_PVNN_MAIN_CPU0_EN")
	)
	(via
		(at 431.304192 -179.238148)
		(size 0.508)
		(drill 0.254)
		(layers "F.Cu" "B.Cu")
		(net "FM_PVNN_MAIN_CPU0_EN")
	)
	(via
		(at 449.152518 -174.33925)
		(size 0.508)
		(drill 0.254)
		(layers "F.Cu" "B.Cu")
		(net "FM_PVNN_MAIN_CPU0_EN")
	)
	(via
		(at 417.25088 -142.458948)
		(size 0.508)
		(drill 0.254)
		(layers "F.Cu" "B.Cu")
		(net "FM_PVNN_MAIN_CPU0_EN")
	)
	(via
		(at 171.50588 -132.552948)
		(size 0.508)
		(drill 0.254)
		(layers "F.Cu" "B.Cu")
		(net "FM_PVNN_MAIN_CPU0_EN")
	)
	(segment
		(start 431.304192 -179.238148)
		(end 432.325018 -178.217322)
		(width 0.12954)
		(layer "B.Cu")
		(net "FM_PVNN_MAIN_CPU0_EN")
	)
	(segment
		(start 432.325018 -178.217322)
		(end 432.325018 -177.55616)
		(width 0.12954)
		(layer "B.Cu")
		(net "FM_PVNN_MAIN_CPU0_EN")
	)
	(segment
		(start 436.642002 -177.46218)
		(end 439.312812 -174.79137)
		(width 0.12954)
		(layer "B.Cu")
		(net "FM_PVNN_MAIN_CPU0_EN")
	)
	(segment
		(start 434.354478 -177.55616)
		(end 434.448458 -177.46218)
		(width 0.12954)
		(layer "B.Cu")
		(net "FM_PVNN_MAIN_CPU0_EN")
	)
	(segment
		(start 433.328318 -177.55616)
		(end 434.354478 -177.55616)
		(width 0.12954)
		(layer "B.Cu")
		(net "FM_PVNN_MAIN_CPU0_EN")
	)
	(segment
		(start 432.325018 -177.55616)
		(end 433.328318 -177.55616)
		(width 0.12954)
		(layer "B.Cu")
		(net "FM_PVNN_MAIN_CPU0_EN")
	)
	(segment
		(start 448.700398 -174.79137)
		(end 449.152518 -174.33925)
		(width 0.12954)
		(layer "B.Cu")
		(net "FM_PVNN_MAIN_CPU0_EN")
	)
	(segment
		(start 439.312812 -174.79137)
		(end 448.700398 -174.79137)
		(width 0.12954)
		(layer "B.Cu")
		(net "FM_PVNN_MAIN_CPU0_EN")
	)
	(segment
		(start 434.448458 -177.46218)
		(end 436.642002 -177.46218)
		(width 0.12954)
		(layer "B.Cu")
		(net "FM_PVNN_MAIN_CPU0_EN")
	)
	(segment
		(start 192.041272 -132.972556)
		(end 190.77178 -134.242048)
		(width 0.127)
		(layer "In13.Cu")
		(net "FM_PVNN_MAIN_CPU0_EN")
	)
	(segment
		(start 202.74788 -133.314948)
		(end 196.65188 -133.314948)
		(width 0.127)
		(layer "In13.Cu")
		(net "FM_PVNN_MAIN_CPU0_EN")
	)
	(segment
		(start 416.98418 -142.725648)
		(end 351.60966 -142.725648)
		(width 0.127)
		(layer "In13.Cu")
		(net "FM_PVNN_MAIN_CPU0_EN")
	)
	(segment
		(start 243.340128 -147.030948)
		(end 242.554252 -146.245072)
		(width 0.127)
		(layer "In13.Cu")
		(net "FM_PVNN_MAIN_CPU0_EN")
	)
	(segment
		(start 179.63388 -133.314948)
		(end 172.26788 -133.314948)
		(width 0.127)
		(layer "In13.Cu")
		(net "FM_PVNN_MAIN_CPU0_EN")
	)
	(segment
		(start 196.309488 -132.972556)
		(end 192.041272 -132.972556)
		(width 0.127)
		(layer "In13.Cu")
		(net "FM_PVNN_MAIN_CPU0_EN")
	)
	(segment
		(start 190.77178 -134.242048)
		(end 186.152028 -134.242048)
		(width 0.127)
		(layer "In13.Cu")
		(net "FM_PVNN_MAIN_CPU0_EN")
	)
	(segment
		(start 185.951876 -134.4422)
		(end 180.761132 -134.4422)
		(width 0.127)
		(layer "In13.Cu")
		(net "FM_PVNN_MAIN_CPU0_EN")
	)
	(segment
		(start 196.65188 -133.314948)
		(end 196.309488 -132.972556)
		(width 0.127)
		(layer "In13.Cu")
		(net "FM_PVNN_MAIN_CPU0_EN")
	)
	(segment
		(start 347.30436 -147.030948)
		(end 243.340128 -147.030948)
		(width 0.127)
		(layer "In13.Cu")
		(net "FM_PVNN_MAIN_CPU0_EN")
	)
	(segment
		(start 242.554252 -146.245072)
		(end 215.678004 -146.245072)
		(width 0.127)
		(layer "In13.Cu")
		(net "FM_PVNN_MAIN_CPU0_EN")
	)
	(segment
		(start 172.26788 -133.314948)
		(end 171.50588 -132.552948)
		(width 0.127)
		(layer "In13.Cu")
		(net "FM_PVNN_MAIN_CPU0_EN")
	)
	(segment
		(start 215.678004 -146.245072)
		(end 202.74788 -133.314948)
		(width 0.127)
		(layer "In13.Cu")
		(net "FM_PVNN_MAIN_CPU0_EN")
	)
	(segment
		(start 180.761132 -134.4422)
		(end 179.63388 -133.314948)
		(width 0.127)
		(layer "In13.Cu")
		(net "FM_PVNN_MAIN_CPU0_EN")
	)
	(segment
		(start 186.152028 -134.242048)
		(end 185.951876 -134.4422)
		(width 0.127)
		(layer "In13.Cu")
		(net "FM_PVNN_MAIN_CPU0_EN")
	)
	(segment
		(start 351.60966 -142.725648)
		(end 347.30436 -147.030948)
		(width 0.127)
		(layer "In13.Cu")
		(net "FM_PVNN_MAIN_CPU0_EN")
	)
	(segment
		(start 417.25088 -142.458948)
		(end 416.98418 -142.725648)
		(width 0.127)
		(layer "In13.Cu")
		(net "FM_PVNN_MAIN_CPU0_EN")
	)
	(segment
		(start 430.71288 -173.032928)
		(end 435.90718 -167.838628)
		(width 0.127)
		(layer "In15.Cu")
		(net "FM_PVNN_MAIN_CPU0_EN")
	)
	(segment
		(start 419.05428 -146.522948)
		(end 417.25088 -144.719548)
		(width 0.127)
		(layer "In15.Cu")
		(net "FM_PVNN_MAIN_CPU0_EN")
	)
	(segment
		(start 434.12918 -160.724088)
		(end 434.12918 -153.449528)
		(width 0.127)
		(layer "In15.Cu")
		(net "FM_PVNN_MAIN_CPU0_EN")
	)
	(segment
		(start 435.90718 -162.502088)
		(end 434.12918 -160.724088)
		(width 0.127)
		(layer "In15.Cu")
		(net "FM_PVNN_MAIN_CPU0_EN")
	)
	(segment
		(start 430.71288 -178.646836)
		(end 430.71288 -173.032928)
		(width 0.127)
		(layer "In15.Cu")
		(net "FM_PVNN_MAIN_CPU0_EN")
	)
	(segment
		(start 417.25088 -144.719548)
		(end 417.25088 -142.458948)
		(width 0.127)
		(layer "In15.Cu")
		(net "FM_PVNN_MAIN_CPU0_EN")
	)
	(segment
		(start 431.304192 -179.238148)
		(end 430.71288 -178.646836)
		(width 0.127)
		(layer "In15.Cu")
		(net "FM_PVNN_MAIN_CPU0_EN")
	)
	(segment
		(start 427.2026 -146.522948)
		(end 419.05428 -146.522948)
		(width 0.127)
		(layer "In15.Cu")
		(net "FM_PVNN_MAIN_CPU0_EN")
	)
	(segment
		(start 434.12918 -153.449528)
		(end 427.2026 -146.522948)
		(width 0.127)
		(layer "In15.Cu")
		(net "FM_PVNN_MAIN_CPU0_EN")
	)
	(segment
		(start 435.90718 -167.838628)
		(end 435.90718 -162.502088)
		(width 0.127)
		(layer "In15.Cu")
		(net "FM_PVNN_MAIN_CPU0_EN")
	)
	(segment
		(start 173.355762 -120.175528)
		(end 172.955712 -120.575578)
		(width 0.12954)
		(layer "F.Cu")
		(net "FM_PVCCIN_CPU1_R_EN")
	)
	(via
		(at 172.955712 -120.575578)
		(size 0.4572)
		(drill 0.254)
		(layers "F.Cu" "B.Cu")
		(net "FM_PVCCIN_CPU1_R_EN")
	)
	(via
		(at 167.06596 -120.175528)
		(size 0.6604)
		(drill 0.3302)
		(layers "F.Cu" "B.Cu")
		(net "FM_PVCCIN_CPU1_R_EN")
	)
	(segment
		(start 172.555662 -120.175528)
		(end 172.955712 -120.575578)
		(width 0.12954)
		(layer "B.Cu")
		(net "FM_PVCCIN_CPU1_R_EN")
	)
	(segment
		(start 171.31538 -119.58066)
		(end 171.910248 -120.175528)
		(width 0.12954)
		(layer "B.Cu")
		(net "FM_PVCCIN_CPU1_R_EN")
	)
	(segment
		(start 167.06596 -120.175528)
		(end 169.516552 -120.175528)
		(width 0.12954)
		(layer "B.Cu")
		(net "FM_PVCCIN_CPU1_R_EN")
	)
	(segment
		(start 164.698426 -119.471948)
		(end 161.548826 -119.471948)
		(width 0.12954)
		(layer "B.Cu")
		(net "FM_PVCCIN_CPU1_R_EN")
	)
	(segment
		(start 161.23793 -119.782844)
		(end 161.23793 -120.106948)
		(width 0.12954)
		(layer "B.Cu")
		(net "FM_PVCCIN_CPU1_R_EN")
	)
	(segment
		(start 170.11142 -119.58066)
		(end 171.31538 -119.58066)
		(width 0.12954)
		(layer "B.Cu")
		(net "FM_PVCCIN_CPU1_R_EN")
	)
	(segment
		(start 165.04793 -119.821452)
		(end 164.698426 -119.471948)
		(width 0.12954)
		(layer "B.Cu")
		(net "FM_PVCCIN_CPU1_R_EN")
	)
	(segment
		(start 171.910248 -120.175528)
		(end 172.555662 -120.175528)
		(width 0.12954)
		(layer "B.Cu")
		(net "FM_PVCCIN_CPU1_R_EN")
	)
	(segment
		(start 161.548826 -119.471948)
		(end 161.23793 -119.782844)
		(width 0.12954)
		(layer "B.Cu")
		(net "FM_PVCCIN_CPU1_R_EN")
	)
	(segment
		(start 169.516552 -120.175528)
		(end 170.11142 -119.58066)
		(width 0.12954)
		(layer "B.Cu")
		(net "FM_PVCCIN_CPU1_R_EN")
	)
	(segment
		(start 165.04793 -120.106948)
		(end 165.04793 -119.821452)
		(width 0.12954)
		(layer "B.Cu")
		(net "FM_PVCCIN_CPU1_R_EN")
	)
	(segment
		(start 165.11651 -120.175528)
		(end 165.04793 -120.106948)
		(width 0.12954)
		(layer "B.Cu")
		(net "FM_PVCCIN_CPU1_R_EN")
	)
	(segment
		(start 167.06596 -120.175528)
		(end 165.11651 -120.175528)
		(width 0.12954)
		(layer "B.Cu")
		(net "FM_PVCCIN_CPU1_R_EN")
	)
	(segment
		(start 181.97449 -169.941748)
		(end 180.664866 -168.632124)
		(width 0.12954)
		(layer "F.Cu")
		(net "FM_PVCCIN_CPU1_EN")
	)
	(segment
		(start 166.184326 -168.632124)
		(end 162.886644 -167.266112)
		(width 0.12954)
		(layer "F.Cu")
		(net "FM_PVCCIN_CPU1_EN")
	)
	(segment
		(start 201.96048 -169.941748)
		(end 181.97449 -169.941748)
		(width 0.12954)
		(layer "F.Cu")
		(net "FM_PVCCIN_CPU1_EN")
	)
	(segment
		(start 218.67622 -185.438288)
		(end 217.45702 -185.438288)
		(width 0.12954)
		(layer "F.Cu")
		(net "FM_PVCCIN_CPU1_EN")
	)
	(segment
		(start 217.45702 -185.438288)
		(end 201.96048 -169.941748)
		(width 0.12954)
		(layer "F.Cu")
		(net "FM_PVCCIN_CPU1_EN")
	)
	(segment
		(start 180.664866 -168.632124)
		(end 166.184326 -168.632124)
		(width 0.12954)
		(layer "F.Cu")
		(net "FM_PVCCIN_CPU1_EN")
	)
	(segment
		(start 220.17228 -186.934348)
		(end 218.67622 -185.438288)
		(width 0.12954)
		(layer "F.Cu")
		(net "FM_PVCCIN_CPU1_EN")
	)
	(segment
		(start 159.82188 -164.201348)
		(end 159.82188 -163.439348)
		(width 0.12954)
		(layer "F.Cu")
		(net "FM_PVCCIN_CPU1_EN")
	)
	(segment
		(start 220.17228 -187.086748)
		(end 220.17228 -186.934348)
		(width 0.12954)
		(layer "F.Cu")
		(net "FM_PVCCIN_CPU1_EN")
	)
	(segment
		(start 162.886644 -167.266112)
		(end 159.82188 -164.201348)
		(width 0.12954)
		(layer "F.Cu")
		(net "FM_PVCCIN_CPU1_EN")
	)
	(via
		(at 220.17228 -187.086748)
		(size 0.508)
		(drill 0.254)
		(layers "F.Cu" "B.Cu")
		(net "FM_PVCCIN_CPU1_EN")
	)
	(via
		(at 159.08274 -120.117108)
		(size 0.508)
		(drill 0.254)
		(layers "F.Cu" "B.Cu")
		(net "FM_PVCCIN_CPU1_EN")
	)
	(via
		(at 159.82188 -163.439348)
		(size 0.508)
		(drill 0.254)
		(layers "F.Cu" "B.Cu")
		(net "FM_PVCCIN_CPU1_EN")
	)
	(segment
		(start 160.43783 -120.405652)
		(end 160.43783 -120.106948)
		(width 0.12954)
		(layer "B.Cu")
		(net "FM_PVCCIN_CPU1_EN")
	)
	(segment
		(start 118.838218 -356.07371)
		(end 117.47246 -357.439468)
		(width 0.12954)
		(layer "B.Cu")
		(net "FM_PVCCIN_CPU1_EN")
	)
	(segment
		(start 118.5926 -380.643892)
		(end 121.456958 -383.50825)
		(width 0.12954)
		(layer "B.Cu")
		(net "FM_PVCCIN_CPU1_EN")
	)
	(segment
		(start 117.47246 -357.439468)
		(end 117.47246 -367.383568)
		(width 0.12954)
		(layer "B.Cu")
		(net "FM_PVCCIN_CPU1_EN")
	)
	(segment
		(start 221.3483 -194.85483)
		(end 221.3483 -188.694568)
		(width 0.12954)
		(layer "B.Cu")
		(net "FM_PVCCIN_CPU1_EN")
	)
	(segment
		(start 111.765588 -352.52152)
		(end 112.45596 -351.831148)
		(width 0.12954)
		(layer "B.Cu")
		(net "FM_PVCCIN_CPU1_EN")
	)
	(segment
		(start 105.696258 -356.85603)
		(end 108.48594 -354.066348)
		(width 0.12954)
		(layer "B.Cu")
		(net "FM_PVCCIN_CPU1_EN")
	)
	(segment
		(start 108.48594 -354.066348)
		(end 111.4044 -354.066348)
		(width 0.12954)
		(layer "B.Cu")
		(net "FM_PVCCIN_CPU1_EN")
	)
	(segment
		(start 229.808278 -238.842042)
		(end 229.808278 -203.314808)
		(width 0.12954)
		(layer "B.Cu")
		(net "FM_PVCCIN_CPU1_EN")
	)
	(segment
		(start 117.422168 -353.378516)
		(end 118.838218 -354.794566)
		(width 0.12954)
		(layer "B.Cu")
		(net "FM_PVCCIN_CPU1_EN")
	)
	(segment
		(start 159.58312 -120.617488)
		(end 160.225994 -120.617488)
		(width 0.12954)
		(layer "B.Cu")
		(net "FM_PVCCIN_CPU1_EN")
	)
	(segment
		(start 112.45596 -351.831148)
		(end 113.387632 -351.831148)
		(width 0.12954)
		(layer "B.Cu")
		(net "FM_PVCCIN_CPU1_EN")
	)
	(segment
		(start 159.08274 -120.117108)
		(end 159.58312 -120.617488)
		(width 0.12954)
		(layer "B.Cu")
		(net "FM_PVCCIN_CPU1_EN")
	)
	(segment
		(start 111.765588 -353.70516)
		(end 111.765588 -352.52152)
		(width 0.12954)
		(layer "B.Cu")
		(net "FM_PVCCIN_CPU1_EN")
	)
	(segment
		(start 221.3483 -188.694568)
		(end 220.17228 -187.518548)
		(width 0.12954)
		(layer "B.Cu")
		(net "FM_PVCCIN_CPU1_EN")
	)
	(segment
		(start 105.696258 -357.65486)
		(end 105.696258 -356.85603)
		(width 0.12954)
		(layer "B.Cu")
		(net "FM_PVCCIN_CPU1_EN")
	)
	(segment
		(start 118.5926 -368.503708)
		(end 118.5926 -380.643892)
		(width 0.12954)
		(layer "B.Cu")
		(net "FM_PVCCIN_CPU1_EN")
	)
	(segment
		(start 114.935 -353.378516)
		(end 117.422168 -353.378516)
		(width 0.12954)
		(layer "B.Cu")
		(net "FM_PVCCIN_CPU1_EN")
	)
	(segment
		(start 209.214974 -335.914746)
		(end 218.993974 -335.914746)
		(width 0.12954)
		(layer "B.Cu")
		(net "FM_PVCCIN_CPU1_EN")
	)
	(segment
		(start 229.808278 -203.314808)
		(end 221.3483 -194.85483)
		(width 0.12954)
		(layer "B.Cu")
		(net "FM_PVCCIN_CPU1_EN")
	)
	(segment
		(start 118.838218 -354.794566)
		(end 118.838218 -356.07371)
		(width 0.12954)
		(layer "B.Cu")
		(net "FM_PVCCIN_CPU1_EN")
	)
	(segment
		(start 174.850298 -383.50825)
		(end 202.555094 -355.803454)
		(width 0.12954)
		(layer "B.Cu")
		(net "FM_PVCCIN_CPU1_EN")
	)
	(segment
		(start 221.705678 -333.203042)
		(end 221.705678 -246.944642)
		(width 0.12954)
		(layer "B.Cu")
		(net "FM_PVCCIN_CPU1_EN")
	)
	(segment
		(start 111.4044 -354.066348)
		(end 111.765588 -353.70516)
		(width 0.12954)
		(layer "B.Cu")
		(net "FM_PVCCIN_CPU1_EN")
	)
	(segment
		(start 202.555094 -355.803454)
		(end 202.555094 -342.574626)
		(width 0.12954)
		(layer "B.Cu")
		(net "FM_PVCCIN_CPU1_EN")
	)
	(segment
		(start 121.456958 -383.50825)
		(end 174.850298 -383.50825)
		(width 0.12954)
		(layer "B.Cu")
		(net "FM_PVCCIN_CPU1_EN")
	)
	(segment
		(start 221.705678 -246.944642)
		(end 229.808278 -238.842042)
		(width 0.12954)
		(layer "B.Cu")
		(net "FM_PVCCIN_CPU1_EN")
	)
	(segment
		(start 117.47246 -367.383568)
		(end 118.5926 -368.503708)
		(width 0.12954)
		(layer "B.Cu")
		(net "FM_PVCCIN_CPU1_EN")
	)
	(segment
		(start 218.993974 -335.914746)
		(end 221.705678 -333.203042)
		(width 0.12954)
		(layer "B.Cu")
		(net "FM_PVCCIN_CPU1_EN")
	)
	(segment
		(start 220.17228 -187.518548)
		(end 220.17228 -187.086748)
		(width 0.12954)
		(layer "B.Cu")
		(net "FM_PVCCIN_CPU1_EN")
	)
	(segment
		(start 160.225994 -120.617488)
		(end 160.43783 -120.405652)
		(width 0.12954)
		(layer "B.Cu")
		(net "FM_PVCCIN_CPU1_EN")
	)
	(segment
		(start 113.387632 -351.831148)
		(end 114.935 -353.378516)
		(width 0.12954)
		(layer "B.Cu")
		(net "FM_PVCCIN_CPU1_EN")
	)
	(segment
		(start 202.555094 -342.574626)
		(end 209.214974 -335.914746)
		(width 0.12954)
		(layer "B.Cu")
		(net "FM_PVCCIN_CPU1_EN")
	)
	(segment
		(start 159.08274 -120.117108)
		(end 158.59252 -120.117108)
		(width 0.127)
		(layer "In2.Cu")
		(net "FM_PVCCIN_CPU1_EN")
	)
	(segment
		(start 157.48 -162.596068)
		(end 158.95828 -164.074348)
		(width 0.127)
		(layer "In2.Cu")
		(net "FM_PVCCIN_CPU1_EN")
	)
	(segment
		(start 157.48 -121.229628)
		(end 157.48 -162.596068)
		(width 0.127)
		(layer "In2.Cu")
		(net "FM_PVCCIN_CPU1_EN")
	)
	(segment
		(start 159.82188 -163.794948)
		(end 159.82188 -163.439348)
		(width 0.127)
		(layer "In2.Cu")
		(net "FM_PVCCIN_CPU1_EN")
	)
	(segment
		(start 158.95828 -164.074348)
		(end 159.54248 -164.074348)
		(width 0.127)
		(layer "In2.Cu")
		(net "FM_PVCCIN_CPU1_EN")
	)
	(segment
		(start 159.54248 -164.074348)
		(end 159.82188 -163.794948)
		(width 0.127)
		(layer "In2.Cu")
		(net "FM_PVCCIN_CPU1_EN")
	)
	(segment
		(start 158.59252 -120.117108)
		(end 157.48 -121.229628)
		(width 0.127)
		(layer "In2.Cu")
		(net "FM_PVCCIN_CPU1_EN")
	)
	(segment
		(start 158.61538 -120.767348)
		(end 157.662626 -120.767348)
		(width 0.12954)
		(layer "F.Cu")
		(net "FM_PVCCIN_CPU0_R_EN")
	)
	(segment
		(start 157.42793 -121.002044)
		(end 157.42793 -121.376948)
		(width 0.12954)
		(layer "F.Cu")
		(net "FM_PVCCIN_CPU0_R_EN")
	)
	(segment
		(start 160.93948 -120.767348)
		(end 158.61538 -120.767348)
		(width 0.12954)
		(layer "F.Cu")
		(net "FM_PVCCIN_CPU0_R_EN")
	)
	(segment
		(start 161.23793 -121.065798)
		(end 160.93948 -120.767348)
		(width 0.12954)
		(layer "F.Cu")
		(net "FM_PVCCIN_CPU0_R_EN")
	)
	(segment
		(start 173.355762 -119.375428)
		(end 172.955712 -119.775478)
		(width 0.12954)
		(layer "F.Cu")
		(net "FM_PVCCIN_CPU0_R_EN")
	)
	(segment
		(start 157.662626 -120.767348)
		(end 157.42793 -121.002044)
		(width 0.12954)
		(layer "F.Cu")
		(net "FM_PVCCIN_CPU0_R_EN")
	)
	(segment
		(start 161.23793 -121.376948)
		(end 161.23793 -121.065798)
		(width 0.12954)
		(layer "F.Cu")
		(net "FM_PVCCIN_CPU0_R_EN")
	)
	(segment
		(start 161.85388 -121.376948)
		(end 161.23793 -121.376948)
		(width 0.12954)
		(layer "F.Cu")
		(net "FM_PVCCIN_CPU0_R_EN")
	)
	(via
		(at 161.85388 -121.376948)
		(size 0.508)
		(drill 0.254)
		(layers "F.Cu" "B.Cu")
		(net "FM_PVCCIN_CPU0_R_EN")
	)
	(via
		(at 158.61538 -120.767348)
		(size 0.762)
		(drill 0.381)
		(layers "F.Cu" "B.Cu")
		(net "FM_PVCCIN_CPU0_R_EN")
	)
	(via
		(at 172.955712 -119.775478)
		(size 0.4572)
		(drill 0.254)
		(layers "F.Cu" "B.Cu")
		(net "FM_PVCCIN_CPU0_R_EN")
	)
	(segment
		(start 170.8785 -121.03862)
		(end 166.296848 -121.03862)
		(width 0.127)
		(layer "In6.Cu")
		(net "FM_PVCCIN_CPU0_R_EN")
	)
	(segment
		(start 166.296848 -121.03862)
		(end 165.35146 -121.984008)
		(width 0.127)
		(layer "In6.Cu")
		(net "FM_PVCCIN_CPU0_R_EN")
	)
	(segment
		(start 171.744132 -120.172988)
		(end 170.8785 -121.03862)
		(width 0.127)
		(layer "In6.Cu")
		(net "FM_PVCCIN_CPU0_R_EN")
	)
	(segment
		(start 165.35146 -121.984008)
		(end 162.46094 -121.984008)
		(width 0.127)
		(layer "In6.Cu")
		(net "FM_PVCCIN_CPU0_R_EN")
	)
	(segment
		(start 172.558202 -120.172988)
		(end 171.744132 -120.172988)
		(width 0.127)
		(layer "In6.Cu")
		(net "FM_PVCCIN_CPU0_R_EN")
	)
	(segment
		(start 172.955712 -119.775478)
		(end 172.558202 -120.172988)
		(width 0.127)
		(layer "In6.Cu")
		(net "FM_PVCCIN_CPU0_R_EN")
	)
	(segment
		(start 162.46094 -121.984008)
		(end 161.85388 -121.376948)
		(width 0.127)
		(layer "In6.Cu")
		(net "FM_PVCCIN_CPU0_R_EN")
	)
	(segment
		(start 156.62783 -121.376948)
		(end 156.01188 -121.376948)
		(width 0.12954)
		(layer "F.Cu")
		(net "FM_PVCCIN_CPU0_EN")
	)
	(via
		(at 156.01188 -121.376948)
		(size 0.508)
		(drill 0.254)
		(layers "F.Cu" "B.Cu")
		(net "FM_PVCCIN_CPU0_EN")
	)
	(via
		(at 208.46288 -125.440948)
		(size 0.508)
		(drill 0.254)
		(layers "F.Cu" "B.Cu")
		(net "FM_PVCCIN_CPU0_EN")
	)
	(via
		(at 348.126558 -361.162346)
		(size 0.508)
		(drill 0.254)
		(layers "F.Cu" "B.Cu")
		(net "FM_PVCCIN_CPU0_EN")
	)
	(via
		(at 241.564922 -202.21956)
		(size 0.508)
		(drill 0.254)
		(layers "F.Cu" "B.Cu")
		(net "FM_PVCCIN_CPU0_EN")
	)
	(via
		(at 301.70882 -387.778752)
		(size 0.508)
		(drill 0.254)
		(layers "F.Cu" "B.Cu")
		(net "FM_PVCCIN_CPU0_EN")
	)
	(segment
		(start 348.126558 -361.162346)
		(end 350.738186 -361.162346)
		(width 0.12954)
		(layer "B.Cu")
		(net "FM_PVCCIN_CPU0_EN")
	)
	(segment
		(start 350.738186 -361.162346)
		(end 350.86798 -361.032552)
		(width 0.12954)
		(layer "B.Cu")
		(net "FM_PVCCIN_CPU0_EN")
	)
	(segment
		(start 350.86798 -361.032552)
		(end 350.86798 -359.995216)
		(width 0.12954)
		(layer "B.Cu")
		(net "FM_PVCCIN_CPU0_EN")
	)
	(segment
		(start 179.2986 -125.024388)
		(end 177.63998 -125.024388)
		(width 0.127)
		(layer "In4.Cu")
		(net "FM_PVCCIN_CPU0_EN")
	)
	(segment
		(start 205.03642 -123.944888)
		(end 200.502774 -123.944888)
		(width 0.127)
		(layer "In4.Cu")
		(net "FM_PVCCIN_CPU0_EN")
	)
	(segment
		(start 301.20082 -387.778752)
		(end 296.546016 -383.123948)
		(width 0.127)
		(layer "In4.Cu")
		(net "FM_PVCCIN_CPU0_EN")
	)
	(segment
		(start 280.57856 -359.240074)
		(end 248.97588 -327.637394)
		(width 0.127)
		(layer "In4.Cu")
		(net "FM_PVCCIN_CPU0_EN")
	)
	(segment
		(start 183.25846 -124.653548)
		(end 179.66944 -124.653548)
		(width 0.127)
		(layer "In4.Cu")
		(net "FM_PVCCIN_CPU0_EN")
	)
	(segment
		(start 208.46288 -125.440948)
		(end 206.53248 -125.440948)
		(width 0.127)
		(layer "In4.Cu")
		(net "FM_PVCCIN_CPU0_EN")
	)
	(segment
		(start 190.790068 -123.988068)
		(end 183.92394 -123.988068)
		(width 0.127)
		(layer "In4.Cu")
		(net "FM_PVCCIN_CPU0_EN")
	)
	(segment
		(start 301.70882 -387.778752)
		(end 301.20082 -387.778752)
		(width 0.127)
		(layer "In4.Cu")
		(net "FM_PVCCIN_CPU0_EN")
	)
	(segment
		(start 251.59208 -212.246718)
		(end 241.564922 -202.21956)
		(width 0.127)
		(layer "In4.Cu")
		(net "FM_PVCCIN_CPU0_EN")
	)
	(segment
		(start 296.546016 -383.123948)
		(end 289.95243 -383.123948)
		(width 0.127)
		(layer "In4.Cu")
		(net "FM_PVCCIN_CPU0_EN")
	)
	(segment
		(start 198.648574 -125.799088)
		(end 195.57746 -125.799088)
		(width 0.127)
		(layer "In4.Cu")
		(net "FM_PVCCIN_CPU0_EN")
	)
	(segment
		(start 248.97588 -327.637394)
		(end 248.97588 -280.876502)
		(width 0.127)
		(layer "In4.Cu")
		(net "FM_PVCCIN_CPU0_EN")
	)
	(segment
		(start 173.84014 -125.103128)
		(end 170.0784 -125.103128)
		(width 0.127)
		(layer "In4.Cu")
		(net "FM_PVCCIN_CPU0_EN")
	)
	(segment
		(start 179.66944 -124.653548)
		(end 179.2986 -125.024388)
		(width 0.127)
		(layer "In4.Cu")
		(net "FM_PVCCIN_CPU0_EN")
	)
	(segment
		(start 289.95243 -383.123948)
		(end 280.57856 -373.750078)
		(width 0.127)
		(layer "In4.Cu")
		(net "FM_PVCCIN_CPU0_EN")
	)
	(segment
		(start 195.57746 -125.799088)
		(end 195.13804 -126.238508)
		(width 0.127)
		(layer "In4.Cu")
		(net "FM_PVCCIN_CPU0_EN")
	)
	(segment
		(start 177.03292 -124.417328)
		(end 174.52594 -124.417328)
		(width 0.127)
		(layer "In4.Cu")
		(net "FM_PVCCIN_CPU0_EN")
	)
	(segment
		(start 251.59208 -278.260302)
		(end 251.59208 -212.246718)
		(width 0.127)
		(layer "In4.Cu")
		(net "FM_PVCCIN_CPU0_EN")
	)
	(segment
		(start 195.13804 -126.238508)
		(end 193.040508 -126.238508)
		(width 0.127)
		(layer "In4.Cu")
		(net "FM_PVCCIN_CPU0_EN")
	)
	(segment
		(start 183.92394 -123.988068)
		(end 183.25846 -124.653548)
		(width 0.127)
		(layer "In4.Cu")
		(net "FM_PVCCIN_CPU0_EN")
	)
	(segment
		(start 166.93642 -121.961148)
		(end 156.59608 -121.961148)
		(width 0.127)
		(layer "In4.Cu")
		(net "FM_PVCCIN_CPU0_EN")
	)
	(segment
		(start 177.63998 -125.024388)
		(end 177.03292 -124.417328)
		(width 0.127)
		(layer "In4.Cu")
		(net "FM_PVCCIN_CPU0_EN")
	)
	(segment
		(start 200.502774 -123.944888)
		(end 198.648574 -125.799088)
		(width 0.127)
		(layer "In4.Cu")
		(net "FM_PVCCIN_CPU0_EN")
	)
	(segment
		(start 156.59608 -121.961148)
		(end 156.01188 -121.376948)
		(width 0.127)
		(layer "In4.Cu")
		(net "FM_PVCCIN_CPU0_EN")
	)
	(segment
		(start 280.57856 -373.750078)
		(end 280.57856 -359.240074)
		(width 0.127)
		(layer "In4.Cu")
		(net "FM_PVCCIN_CPU0_EN")
	)
	(segment
		(start 174.52594 -124.417328)
		(end 173.84014 -125.103128)
		(width 0.127)
		(layer "In4.Cu")
		(net "FM_PVCCIN_CPU0_EN")
	)
	(segment
		(start 206.53248 -125.440948)
		(end 205.03642 -123.944888)
		(width 0.127)
		(layer "In4.Cu")
		(net "FM_PVCCIN_CPU0_EN")
	)
	(segment
		(start 170.0784 -125.103128)
		(end 166.93642 -121.961148)
		(width 0.127)
		(layer "In4.Cu")
		(net "FM_PVCCIN_CPU0_EN")
	)
	(segment
		(start 193.040508 -126.238508)
		(end 190.790068 -123.988068)
		(width 0.127)
		(layer "In4.Cu")
		(net "FM_PVCCIN_CPU0_EN")
	)
	(segment
		(start 248.97588 -280.876502)
		(end 251.59208 -278.260302)
		(width 0.127)
		(layer "In4.Cu")
		(net "FM_PVCCIN_CPU0_EN")
	)
	(segment
		(start 346.437712 -374.617996)
		(end 331.278992 -374.617996)
		(width 0.127)
		(layer "In6.Cu")
		(net "FM_PVCCIN_CPU0_EN")
	)
	(segment
		(start 348.126558 -361.162346)
		(end 347.406722 -361.162346)
		(width 0.127)
		(layer "In6.Cu")
		(net "FM_PVCCIN_CPU0_EN")
	)
	(segment
		(start 318.118236 -387.778752)
		(end 301.70882 -387.778752)
		(width 0.127)
		(layer "In6.Cu")
		(net "FM_PVCCIN_CPU0_EN")
	)
	(segment
		(start 331.278992 -374.617996)
		(end 318.118236 -387.778752)
		(width 0.127)
		(layer "In6.Cu")
		(net "FM_PVCCIN_CPU0_EN")
	)
	(segment
		(start 346.23502 -363.713268)
		(end 349.48114 -366.959388)
		(width 0.127)
		(layer "In6.Cu")
		(net "FM_PVCCIN_CPU0_EN")
	)
	(segment
		(start 349.48114 -366.959388)
		(end 349.48114 -371.574568)
		(width 0.127)
		(layer "In6.Cu")
		(net "FM_PVCCIN_CPU0_EN")
	)
	(segment
		(start 347.406722 -361.162346)
		(end 346.23502 -362.334048)
		(width 0.127)
		(layer "In6.Cu")
		(net "FM_PVCCIN_CPU0_EN")
	)
	(segment
		(start 346.23502 -362.334048)
		(end 346.23502 -363.713268)
		(width 0.127)
		(layer "In6.Cu")
		(net "FM_PVCCIN_CPU0_EN")
	)
	(segment
		(start 349.48114 -371.574568)
		(end 346.437712 -374.617996)
		(width 0.127)
		(layer "In6.Cu")
		(net "FM_PVCCIN_CPU0_EN")
	)
	(segment
		(start 220.141546 -146.432016)
		(end 209.65668 -135.94715)
		(width 0.127)
		(layer "In11.Cu")
		(net "FM_PVCCIN_CPU0_EN")
	)
	(segment
		(start 242.93068 -181.027324)
		(end 220.141546 -158.23819)
		(width 0.127)
		(layer "In11.Cu")
		(net "FM_PVCCIN_CPU0_EN")
	)
	(segment
		(start 209.65668 -129.198624)
		(end 209.02168 -128.563624)
		(width 0.127)
		(layer "In11.Cu")
		(net "FM_PVCCIN_CPU0_EN")
	)
	(segment
		(start 209.65668 -135.94715)
		(end 209.65668 -129.198624)
		(width 0.127)
		(layer "In11.Cu")
		(net "FM_PVCCIN_CPU0_EN")
	)
	(segment
		(start 240.72088 -198.719948)
		(end 242.93068 -196.510148)
		(width 0.127)
		(layer "In11.Cu")
		(net "FM_PVCCIN_CPU0_EN")
	)
	(segment
		(start 220.141546 -158.23819)
		(end 220.141546 -146.432016)
		(width 0.127)
		(layer "In11.Cu")
		(net "FM_PVCCIN_CPU0_EN")
	)
	(segment
		(start 241.564922 -202.21956)
		(end 240.72088 -201.375518)
		(width 0.127)
		(layer "In11.Cu")
		(net "FM_PVCCIN_CPU0_EN")
	)
	(segment
		(start 209.02168 -128.563624)
		(end 209.02168 -125.999748)
		(width 0.127)
		(layer "In11.Cu")
		(net "FM_PVCCIN_CPU0_EN")
	)
	(segment
		(start 242.93068 -196.510148)
		(end 242.93068 -181.027324)
		(width 0.127)
		(layer "In11.Cu")
		(net "FM_PVCCIN_CPU0_EN")
	)
	(segment
		(start 240.72088 -201.375518)
		(end 240.72088 -198.719948)
		(width 0.127)
		(layer "In11.Cu")
		(net "FM_PVCCIN_CPU0_EN")
	)
	(segment
		(start 209.02168 -125.999748)
		(end 208.46288 -125.440948)
		(width 0.127)
		(layer "In11.Cu")
		(net "FM_PVCCIN_CPU0_EN")
	)
	(segment
		(start 172.555662 -120.175528)
		(end 172.155612 -120.575578)
		(width 0.12954)
		(layer "F.Cu")
		(net "FM_PVCCINFAON_CPU1_R_EN")
	)
	(via
		(at 172.155612 -120.575578)
		(size 0.4572)
		(drill 0.254)
		(layers "F.Cu" "B.Cu")
		(net "FM_PVCCINFAON_CPU1_R_EN")
	)
	(via
		(at 168.69156 -120.741948)
		(size 0.6604)
		(drill 0.3302)
		(layers "F.Cu" "B.Cu")
		(net "FM_PVCCINFAON_CPU1_R_EN")
	)
	(segment
		(start 168.69156 -120.741948)
		(end 166.17188 -120.741948)
		(width 0.12954)
		(layer "B.Cu")
		(net "FM_PVCCINFAON_CPU1_R_EN")
	)
	(segment
		(start 169.623232 -120.741948)
		(end 170.32478 -120.0404)
		(width 0.12954)
		(layer "B.Cu")
		(net "FM_PVCCINFAON_CPU1_R_EN")
	)
	(segment
		(start 164.769546 -120.711468)
		(end 165.04793 -120.989852)
		(width 0.12954)
		(layer "B.Cu")
		(net "FM_PVCCINFAON_CPU1_R_EN")
	)
	(segment
		(start 171.13758 -120.0404)
		(end 171.68876 -120.59158)
		(width 0.12954)
		(layer "B.Cu")
		(net "FM_PVCCINFAON_CPU1_R_EN")
	)
	(segment
		(start 168.69156 -120.741948)
		(end 169.623232 -120.741948)
		(width 0.12954)
		(layer "B.Cu")
		(net "FM_PVCCINFAON_CPU1_R_EN")
	)
	(segment
		(start 170.32478 -120.0404)
		(end 171.13758 -120.0404)
		(width 0.12954)
		(layer "B.Cu")
		(net "FM_PVCCINFAON_CPU1_R_EN")
	)
	(segment
		(start 171.68876 -120.59158)
		(end 172.13961 -120.59158)
		(width 0.12954)
		(layer "B.Cu")
		(net "FM_PVCCINFAON_CPU1_R_EN")
	)
	(segment
		(start 172.13961 -120.59158)
		(end 172.155612 -120.575578)
		(width 0.12954)
		(layer "B.Cu")
		(net "FM_PVCCINFAON_CPU1_R_EN")
	)
	(segment
		(start 161.23793 -121.027444)
		(end 161.553906 -120.711468)
		(width 0.12954)
		(layer "B.Cu")
		(net "FM_PVCCINFAON_CPU1_R_EN")
	)
	(segment
		(start 166.17188 -120.741948)
		(end 165.53688 -121.376948)
		(width 0.12954)
		(layer "B.Cu")
		(net "FM_PVCCINFAON_CPU1_R_EN")
	)
	(segment
		(start 161.553906 -120.711468)
		(end 164.769546 -120.711468)
		(width 0.12954)
		(layer "B.Cu")
		(net "FM_PVCCINFAON_CPU1_R_EN")
	)
	(segment
		(start 165.04793 -120.989852)
		(end 165.04793 -121.376948)
		(width 0.12954)
		(layer "B.Cu")
		(net "FM_PVCCINFAON_CPU1_R_EN")
	)
	(segment
		(start 161.23793 -121.376948)
		(end 161.23793 -121.027444)
		(width 0.12954)
		(layer "B.Cu")
		(net "FM_PVCCINFAON_CPU1_R_EN")
	)
	(segment
		(start 165.53688 -121.376948)
		(end 165.04793 -121.376948)
		(width 0.12954)
		(layer "B.Cu")
		(net "FM_PVCCINFAON_CPU1_R_EN")
	)
	(via
		(at 139.39012 -120.886728)
		(size 0.508)
		(drill 0.254)
		(layers "F.Cu" "B.Cu")
		(net "FM_PVCCINFAON_CPU1_EN")
	)
	(via
		(at 40.961818 -127.798322)
		(size 0.508)
		(drill 0.254)
		(layers "F.Cu" "B.Cu")
		(net "FM_PVCCINFAON_CPU1_EN")
	)
	(via
		(at 159.05734 -121.412508)
		(size 0.508)
		(drill 0.254)
		(layers "F.Cu" "B.Cu")
		(net "FM_PVCCINFAON_CPU1_EN")
	)
	(segment
		(start 39.032942 -127.798322)
		(end 40.961818 -127.798322)
		(width 0.12954)
		(layer "B.Cu")
		(net "FM_PVCCINFAON_CPU1_EN")
	)
	(segment
		(start 160.182814 -121.879868)
		(end 160.43783 -121.624852)
		(width 0.12954)
		(layer "B.Cu")
		(net "FM_PVCCINFAON_CPU1_EN")
	)
	(segment
		(start 160.43783 -121.624852)
		(end 160.43783 -121.376948)
		(width 0.12954)
		(layer "B.Cu")
		(net "FM_PVCCINFAON_CPU1_EN")
	)
	(segment
		(start 159.05734 -121.412508)
		(end 159.5247 -121.879868)
		(width 0.12954)
		(layer "B.Cu")
		(net "FM_PVCCINFAON_CPU1_EN")
	)
	(segment
		(start 159.5247 -121.879868)
		(end 160.182814 -121.879868)
		(width 0.12954)
		(layer "B.Cu")
		(net "FM_PVCCINFAON_CPU1_EN")
	)
	(segment
		(start 38.45306 -127.21844)
		(end 39.032942 -127.798322)
		(width 0.12954)
		(layer "B.Cu")
		(net "FM_PVCCINFAON_CPU1_EN")
	)
	(segment
		(start 37.567108 -127.21844)
		(end 38.45306 -127.21844)
		(width 0.12954)
		(layer "B.Cu")
		(net "FM_PVCCINFAON_CPU1_EN")
	)
	(segment
		(start 37.368988 -127.41656)
		(end 37.567108 -127.21844)
		(width 0.12954)
		(layer "B.Cu")
		(net "FM_PVCCINFAON_CPU1_EN")
	)
	(segment
		(start 152.608788 -120.452388)
		(end 154.041348 -121.884948)
		(width 0.127)
		(layer "In6.Cu")
		(net "FM_PVCCINFAON_CPU1_EN")
	)
	(segment
		(start 149.72538 -119.5705)
		(end 150.607268 -120.452388)
		(width 0.127)
		(layer "In6.Cu")
		(net "FM_PVCCINFAON_CPU1_EN")
	)
	(segment
		(start 140.167868 -120.10898)
		(end 147.43938 -120.10898)
		(width 0.127)
		(layer "In6.Cu")
		(net "FM_PVCCINFAON_CPU1_EN")
	)
	(segment
		(start 147.43938 -120.10898)
		(end 147.97786 -119.5705)
		(width 0.127)
		(layer "In6.Cu")
		(net "FM_PVCCINFAON_CPU1_EN")
	)
	(segment
		(start 156.61894 -121.884948)
		(end 157.09138 -121.412508)
		(width 0.127)
		(layer "In6.Cu")
		(net "FM_PVCCINFAON_CPU1_EN")
	)
	(segment
		(start 157.09138 -121.412508)
		(end 159.05734 -121.412508)
		(width 0.127)
		(layer "In6.Cu")
		(net "FM_PVCCINFAON_CPU1_EN")
	)
	(segment
		(start 139.39012 -120.886728)
		(end 140.167868 -120.10898)
		(width 0.127)
		(layer "In6.Cu")
		(net "FM_PVCCINFAON_CPU1_EN")
	)
	(segment
		(start 150.607268 -120.452388)
		(end 152.608788 -120.452388)
		(width 0.127)
		(layer "In6.Cu")
		(net "FM_PVCCINFAON_CPU1_EN")
	)
	(segment
		(start 154.041348 -121.884948)
		(end 156.61894 -121.884948)
		(width 0.127)
		(layer "In6.Cu")
		(net "FM_PVCCINFAON_CPU1_EN")
	)
	(segment
		(start 147.97786 -119.5705)
		(end 149.72538 -119.5705)
		(width 0.127)
		(layer "In6.Cu")
		(net "FM_PVCCINFAON_CPU1_EN")
	)
	(segment
		(start 130.931666 -118.993412)
		(end 110.962694 -118.993412)
		(width 0.127)
		(layer "In13.Cu")
		(net "FM_PVCCINFAON_CPU1_EN")
	)
	(segment
		(start 132.858002 -120.919748)
		(end 130.931666 -118.993412)
		(width 0.127)
		(layer "In13.Cu")
		(net "FM_PVCCINFAON_CPU1_EN")
	)
	(segment
		(start 139.39012 -120.886728)
		(end 138.7983 -120.294908)
		(width 0.127)
		(layer "In13.Cu")
		(net "FM_PVCCINFAON_CPU1_EN")
	)
	(segment
		(start 105.829354 -124.126752)
		(end 44.016676 -124.126752)
		(width 0.127)
		(layer "In13.Cu")
		(net "FM_PVCCINFAON_CPU1_EN")
	)
	(segment
		(start 135.32612 -120.294908)
		(end 134.70128 -120.919748)
		(width 0.127)
		(layer "In13.Cu")
		(net "FM_PVCCINFAON_CPU1_EN")
	)
	(segment
		(start 110.962694 -118.993412)
		(end 105.829354 -124.126752)
		(width 0.127)
		(layer "In13.Cu")
		(net "FM_PVCCINFAON_CPU1_EN")
	)
	(segment
		(start 138.7983 -120.294908)
		(end 135.32612 -120.294908)
		(width 0.127)
		(layer "In13.Cu")
		(net "FM_PVCCINFAON_CPU1_EN")
	)
	(segment
		(start 44.016676 -124.126752)
		(end 40.961818 -127.18161)
		(width 0.127)
		(layer "In13.Cu")
		(net "FM_PVCCINFAON_CPU1_EN")
	)
	(segment
		(start 40.961818 -127.18161)
		(end 40.961818 -127.798322)
		(width 0.127)
		(layer "In13.Cu")
		(net "FM_PVCCINFAON_CPU1_EN")
	)
	(segment
		(start 134.70128 -120.919748)
		(end 132.858002 -120.919748)
		(width 0.127)
		(layer "In13.Cu")
		(net "FM_PVCCINFAON_CPU1_EN")
	)
	(segment
		(start 161.23793 -120.106948)
		(end 161.23793 -119.745252)
		(width 0.12954)
		(layer "F.Cu")
		(net "FM_PVCCINFAON_CPU0_R_EN")
	)
	(segment
		(start 172.555662 -119.375428)
		(end 172.155612 -119.775478)
		(width 0.12954)
		(layer "F.Cu")
		(net "FM_PVCCINFAON_CPU0_R_EN")
	)
	(segment
		(start 160.964626 -119.471948)
		(end 158.61284 -119.471948)
		(width 0.12954)
		(layer "F.Cu")
		(net "FM_PVCCINFAON_CPU0_R_EN")
	)
	(segment
		(start 157.42793 -119.732044)
		(end 157.42793 -120.106948)
		(width 0.12954)
		(layer "F.Cu")
		(net "FM_PVCCINFAON_CPU0_R_EN")
	)
	(segment
		(start 158.61284 -119.471948)
		(end 157.688026 -119.471948)
		(width 0.12954)
		(layer "F.Cu")
		(net "FM_PVCCINFAON_CPU0_R_EN")
	)
	(segment
		(start 161.23793 -119.745252)
		(end 160.964626 -119.471948)
		(width 0.12954)
		(layer "F.Cu")
		(net "FM_PVCCINFAON_CPU0_R_EN")
	)
	(segment
		(start 157.688026 -119.471948)
		(end 157.42793 -119.732044)
		(width 0.12954)
		(layer "F.Cu")
		(net "FM_PVCCINFAON_CPU0_R_EN")
	)
	(segment
		(start 161.85388 -120.106948)
		(end 161.23793 -120.106948)
		(width 0.12954)
		(layer "F.Cu")
		(net "FM_PVCCINFAON_CPU0_R_EN")
	)
	(via
		(at 172.155612 -119.775478)
		(size 0.4572)
		(drill 0.254)
		(layers "F.Cu" "B.Cu")
		(net "FM_PVCCINFAON_CPU0_R_EN")
	)
	(via
		(at 158.61284 -119.471948)
		(size 0.762)
		(drill 0.381)
		(layers "F.Cu" "B.Cu")
		(net "FM_PVCCINFAON_CPU0_R_EN")
	)
	(via
		(at 161.85388 -120.106948)
		(size 0.508)
		(drill 0.254)
		(layers "F.Cu" "B.Cu")
		(net "FM_PVCCINFAON_CPU0_R_EN")
	)
	(segment
		(start 170.510962 -119.775478)
		(end 169.75836 -120.52808)
		(width 0.127)
		(layer "In6.Cu")
		(net "FM_PVCCINFAON_CPU0_R_EN")
	)
	(segment
		(start 162.0012 -120.106948)
		(end 161.85388 -120.106948)
		(width 0.127)
		(layer "In6.Cu")
		(net "FM_PVCCINFAON_CPU0_R_EN")
	)
	(segment
		(start 166.152068 -120.52808)
		(end 166.02202 -120.658128)
		(width 0.127)
		(layer "In6.Cu")
		(net "FM_PVCCINFAON_CPU0_R_EN")
	)
	(segment
		(start 172.155612 -119.775478)
		(end 170.510962 -119.775478)
		(width 0.127)
		(layer "In6.Cu")
		(net "FM_PVCCINFAON_CPU0_R_EN")
	)
	(segment
		(start 162.55238 -120.658128)
		(end 162.0012 -120.106948)
		(width 0.127)
		(layer "In6.Cu")
		(net "FM_PVCCINFAON_CPU0_R_EN")
	)
	(segment
		(start 169.75836 -120.52808)
		(end 166.152068 -120.52808)
		(width 0.127)
		(layer "In6.Cu")
		(net "FM_PVCCINFAON_CPU0_R_EN")
	)
	(segment
		(start 166.02202 -120.658128)
		(end 162.55238 -120.658128)
		(width 0.127)
		(layer "In6.Cu")
		(net "FM_PVCCINFAON_CPU0_R_EN")
	)
	(segment
		(start 156.62783 -120.106948)
		(end 156.01188 -120.106948)
		(width 0.12954)
		(layer "F.Cu")
		(net "FM_PVCCINFAON_CPU0_EN")
	)
	(via
		(at 156.01188 -120.106948)
		(size 0.508)
		(drill 0.254)
		(layers "F.Cu" "B.Cu")
		(net "FM_PVCCINFAON_CPU0_EN")
	)
	(via
		(at 432.54422 -133.629908)
		(size 0.508)
		(drill 0.254)
		(layers "F.Cu" "B.Cu")
		(net "FM_PVCCINFAON_CPU0_EN")
	)
	(segment
		(start 432.19751 -133.976618)
		(end 431.116994 -133.976618)
		(width 0.12954)
		(layer "B.Cu")
		(net "FM_PVCCINFAON_CPU0_EN")
	)
	(segment
		(start 431.116994 -133.976618)
		(end 431.000154 -134.093458)
		(width 0.12954)
		(layer "B.Cu")
		(net "FM_PVCCINFAON_CPU0_EN")
	)
	(segment
		(start 432.54422 -133.629908)
		(end 432.19751 -133.976618)
		(width 0.12954)
		(layer "B.Cu")
		(net "FM_PVCCINFAON_CPU0_EN")
	)
	(segment
		(start 431.000154 -134.093458)
		(end 431.000154 -134.494778)
		(width 0.12954)
		(layer "B.Cu")
		(net "FM_PVCCINFAON_CPU0_EN")
	)
	(segment
		(start 194.79006 -121.224548)
		(end 204.200252 -121.224548)
		(width 0.127)
		(layer "In13.Cu")
		(net "FM_PVCCINFAON_CPU0_EN")
	)
	(segment
		(start 445.52108 -117.891306)
		(end 445.52108 -126.31293)
		(width 0.127)
		(layer "In13.Cu")
		(net "FM_PVCCINFAON_CPU0_EN")
	)
	(segment
		(start 240.67008 -113.294668)
		(end 243.3574 -115.981988)
		(width 0.127)
		(layer "In13.Cu")
		(net "FM_PVCCINFAON_CPU0_EN")
	)
	(segment
		(start 443.433962 -128.400048)
		(end 439.05678 -128.400048)
		(width 0.127)
		(layer "In13.Cu")
		(net "FM_PVCCINFAON_CPU0_EN")
	)
	(segment
		(start 247.21312 -115.981988)
		(end 253.03988 -121.808748)
		(width 0.127)
		(layer "In13.Cu")
		(net "FM_PVCCINFAON_CPU0_EN")
	)
	(segment
		(start 167.42918 -122.050048)
		(end 167.7162 -121.763028)
		(width 0.127)
		(layer "In13.Cu")
		(net "FM_PVCCINFAON_CPU0_EN")
	)
	(segment
		(start 209.9056 -119.6848)
		(end 211.6328 -117.9576)
		(width 0.127)
		(layer "In13.Cu")
		(net "FM_PVCCINFAON_CPU0_EN")
	)
	(segment
		(start 157.95498 -122.050048)
		(end 167.42918 -122.050048)
		(width 0.127)
		(layer "In13.Cu")
		(net "FM_PVCCINFAON_CPU0_EN")
	)
	(segment
		(start 253.03988 -121.808748)
		(end 416.26028 -121.808748)
		(width 0.127)
		(layer "In13.Cu")
		(net "FM_PVCCINFAON_CPU0_EN")
	)
	(segment
		(start 433.82692 -133.629908)
		(end 432.54422 -133.629908)
		(width 0.127)
		(layer "In13.Cu")
		(net "FM_PVCCINFAON_CPU0_EN")
	)
	(segment
		(start 193.8401 -121.376948)
		(end 194.63766 -121.376948)
		(width 0.127)
		(layer "In13.Cu")
		(net "FM_PVCCINFAON_CPU0_EN")
	)
	(segment
		(start 171.75226 -121.884948)
		(end 177.59934 -121.884948)
		(width 0.127)
		(layer "In13.Cu")
		(net "FM_PVCCINFAON_CPU0_EN")
	)
	(segment
		(start 177.59934 -121.884948)
		(end 178.51374 -120.970548)
		(width 0.127)
		(layer "In13.Cu")
		(net "FM_PVCCINFAON_CPU0_EN")
	)
	(segment
		(start 186.49188 -120.970548)
		(end 186.89828 -121.376948)
		(width 0.127)
		(layer "In13.Cu")
		(net "FM_PVCCINFAON_CPU0_EN")
	)
	(segment
		(start 206.629 -119.6086)
		(end 209.1436 -119.6086)
		(width 0.127)
		(layer "In13.Cu")
		(net "FM_PVCCINFAON_CPU0_EN")
	)
	(segment
		(start 445.52108 -126.31293)
		(end 443.433962 -128.400048)
		(width 0.127)
		(layer "In13.Cu")
		(net "FM_PVCCINFAON_CPU0_EN")
	)
	(segment
		(start 193.421 -121.796048)
		(end 193.8401 -121.376948)
		(width 0.127)
		(layer "In13.Cu")
		(net "FM_PVCCINFAON_CPU0_EN")
	)
	(segment
		(start 178.51374 -120.970548)
		(end 186.49188 -120.970548)
		(width 0.127)
		(layer "In13.Cu")
		(net "FM_PVCCINFAON_CPU0_EN")
	)
	(segment
		(start 233.510582 -112.669574)
		(end 236.403642 -112.669574)
		(width 0.127)
		(layer "In13.Cu")
		(net "FM_PVCCINFAON_CPU0_EN")
	)
	(segment
		(start 156.01188 -120.106948)
		(end 157.95498 -122.050048)
		(width 0.127)
		(layer "In13.Cu")
		(net "FM_PVCCINFAON_CPU0_EN")
	)
	(segment
		(start 187.90158 -121.796048)
		(end 193.421 -121.796048)
		(width 0.127)
		(layer "In13.Cu")
		(net "FM_PVCCINFAON_CPU0_EN")
	)
	(segment
		(start 425.25188 -112.817148)
		(end 440.446922 -112.817148)
		(width 0.127)
		(layer "In13.Cu")
		(net "FM_PVCCINFAON_CPU0_EN")
	)
	(segment
		(start 211.6328 -117.9576)
		(end 218.867228 -117.9576)
		(width 0.127)
		(layer "In13.Cu")
		(net "FM_PVCCINFAON_CPU0_EN")
	)
	(segment
		(start 186.89828 -121.376948)
		(end 187.48248 -121.376948)
		(width 0.127)
		(layer "In13.Cu")
		(net "FM_PVCCINFAON_CPU0_EN")
	)
	(segment
		(start 209.1436 -119.6086)
		(end 209.2198 -119.6848)
		(width 0.127)
		(layer "In13.Cu")
		(net "FM_PVCCINFAON_CPU0_EN")
	)
	(segment
		(start 206.1972 -120.0404)
		(end 206.629 -119.6086)
		(width 0.127)
		(layer "In13.Cu")
		(net "FM_PVCCINFAON_CPU0_EN")
	)
	(segment
		(start 209.2198 -119.6848)
		(end 209.9056 -119.6848)
		(width 0.127)
		(layer "In13.Cu")
		(net "FM_PVCCINFAON_CPU0_EN")
	)
	(segment
		(start 218.867228 -117.9576)
		(end 223.584262 -113.240566)
		(width 0.127)
		(layer "In13.Cu")
		(net "FM_PVCCINFAON_CPU0_EN")
	)
	(segment
		(start 223.584262 -113.240566)
		(end 232.93959 -113.240566)
		(width 0.127)
		(layer "In13.Cu")
		(net "FM_PVCCINFAON_CPU0_EN")
	)
	(segment
		(start 167.7162 -121.763028)
		(end 171.63034 -121.763028)
		(width 0.127)
		(layer "In13.Cu")
		(net "FM_PVCCINFAON_CPU0_EN")
	)
	(segment
		(start 205.3844 -120.0404)
		(end 206.1972 -120.0404)
		(width 0.127)
		(layer "In13.Cu")
		(net "FM_PVCCINFAON_CPU0_EN")
	)
	(segment
		(start 187.48248 -121.376948)
		(end 187.90158 -121.796048)
		(width 0.127)
		(layer "In13.Cu")
		(net "FM_PVCCINFAON_CPU0_EN")
	)
	(segment
		(start 232.93959 -113.240566)
		(end 233.510582 -112.669574)
		(width 0.127)
		(layer "In13.Cu")
		(net "FM_PVCCINFAON_CPU0_EN")
	)
	(segment
		(start 439.05678 -128.400048)
		(end 433.82692 -133.629908)
		(width 0.127)
		(layer "In13.Cu")
		(net "FM_PVCCINFAON_CPU0_EN")
	)
	(segment
		(start 416.26028 -121.808748)
		(end 425.25188 -112.817148)
		(width 0.127)
		(layer "In13.Cu")
		(net "FM_PVCCINFAON_CPU0_EN")
	)
	(segment
		(start 440.446922 -112.817148)
		(end 445.52108 -117.891306)
		(width 0.127)
		(layer "In13.Cu")
		(net "FM_PVCCINFAON_CPU0_EN")
	)
	(segment
		(start 171.63034 -121.763028)
		(end 171.75226 -121.884948)
		(width 0.127)
		(layer "In13.Cu")
		(net "FM_PVCCINFAON_CPU0_EN")
	)
	(segment
		(start 236.403642 -112.669574)
		(end 237.028736 -113.294668)
		(width 0.127)
		(layer "In13.Cu")
		(net "FM_PVCCINFAON_CPU0_EN")
	)
	(segment
		(start 237.028736 -113.294668)
		(end 240.67008 -113.294668)
		(width 0.127)
		(layer "In13.Cu")
		(net "FM_PVCCINFAON_CPU0_EN")
	)
	(segment
		(start 243.3574 -115.981988)
		(end 247.21312 -115.981988)
		(width 0.127)
		(layer "In13.Cu")
		(net "FM_PVCCINFAON_CPU0_EN")
	)
	(segment
		(start 204.200252 -121.224548)
		(end 205.3844 -120.0404)
		(width 0.127)
		(layer "In13.Cu")
		(net "FM_PVCCINFAON_CPU0_EN")
	)
	(segment
		(start 194.63766 -121.376948)
		(end 194.79006 -121.224548)
		(width 0.127)
		(layer "In13.Cu")
		(net "FM_PVCCINFAON_CPU0_EN")
	)
	(segment
		(start 172.555662 -120.975374)
		(end 172.155612 -121.375424)
		(width 0.12954)
		(layer "F.Cu")
		(net "FM_PVCCFA_EHV_FIVRA_CPU1_R_EN")
	)
	(via
		(at 172.155612 -121.375424)
		(size 0.4572)
		(drill 0.254)
		(layers "F.Cu" "B.Cu")
		(net "FM_PVCCFA_EHV_FIVRA_CPU1_R_EN")
	)
	(via
		(at 169.06494 -122.596148)
		(size 0.6604)
		(drill 0.3302)
		(layers "F.Cu" "B.Cu")
		(net "FM_PVCCFA_EHV_FIVRA_CPU1_R_EN")
	)
	(segment
		(start 161.680906 -122.646948)
		(end 161.23793 -122.646948)
		(width 0.12954)
		(layer "B.Cu")
		(net "FM_PVCCFA_EHV_FIVRA_CPU1_R_EN")
	)
	(segment
		(start 172.155612 -121.375424)
		(end 171.87926 -121.651776)
		(width 0.12954)
		(layer "B.Cu")
		(net "FM_PVCCFA_EHV_FIVRA_CPU1_R_EN")
	)
	(segment
		(start 161.23793 -123.916948)
		(end 161.23793 -122.646948)
		(width 0.12954)
		(layer "B.Cu")
		(net "FM_PVCCFA_EHV_FIVRA_CPU1_R_EN")
	)
	(segment
		(start 171.53382 -123.49734)
		(end 169.966132 -123.49734)
		(width 0.12954)
		(layer "B.Cu")
		(net "FM_PVCCFA_EHV_FIVRA_CPU1_R_EN")
	)
	(segment
		(start 165.615366 -123.330208)
		(end 162.364166 -123.330208)
		(width 0.12954)
		(layer "B.Cu")
		(net "FM_PVCCFA_EHV_FIVRA_CPU1_R_EN")
	)
	(segment
		(start 162.364166 -123.330208)
		(end 161.680906 -122.646948)
		(width 0.12954)
		(layer "B.Cu")
		(net "FM_PVCCFA_EHV_FIVRA_CPU1_R_EN")
	)
	(segment
		(start 166.349426 -122.596148)
		(end 165.615366 -123.330208)
		(width 0.12954)
		(layer "B.Cu")
		(net "FM_PVCCFA_EHV_FIVRA_CPU1_R_EN")
	)
	(segment
		(start 169.966132 -123.49734)
		(end 169.06494 -122.596148)
		(width 0.12954)
		(layer "B.Cu")
		(net "FM_PVCCFA_EHV_FIVRA_CPU1_R_EN")
	)
	(segment
		(start 171.87926 -123.1519)
		(end 171.53382 -123.49734)
		(width 0.12954)
		(layer "B.Cu")
		(net "FM_PVCCFA_EHV_FIVRA_CPU1_R_EN")
	)
	(segment
		(start 169.06494 -122.596148)
		(end 166.349426 -122.596148)
		(width 0.12954)
		(layer "B.Cu")
		(net "FM_PVCCFA_EHV_FIVRA_CPU1_R_EN")
	)
	(segment
		(start 171.87926 -121.651776)
		(end 171.87926 -123.1519)
		(width 0.12954)
		(layer "B.Cu")
		(net "FM_PVCCFA_EHV_FIVRA_CPU1_R_EN")
	)
	(segment
		(start 101.825552 -354.459032)
		(end 102.138226 -354.459032)
		(width 0.12954)
		(layer "F.Cu")
		(net "FM_PVCCFA_EHV_FIVRA_CPU1_EN")
	)
	(segment
		(start 102.427024 -354.74783)
		(end 102.427024 -354.847652)
		(width 0.12954)
		(layer "F.Cu")
		(net "FM_PVCCFA_EHV_FIVRA_CPU1_EN")
	)
	(segment
		(start 102.138226 -354.459032)
		(end 102.427024 -354.74783)
		(width 0.12954)
		(layer "F.Cu")
		(net "FM_PVCCFA_EHV_FIVRA_CPU1_EN")
	)
	(via
		(at 196.47662 -128.793748)
		(size 0.508)
		(drill 0.254)
		(layers "F.Cu" "B.Cu")
		(net "FM_PVCCFA_EHV_FIVRA_CPU1_EN")
	)
	(via
		(at 159.82188 -123.77674)
		(size 0.508)
		(drill 0.254)
		(layers "F.Cu" "B.Cu")
		(net "FM_PVCCFA_EHV_FIVRA_CPU1_EN")
	)
	(via
		(at 173.71822 -394.985748)
		(size 0.508)
		(drill 0.254)
		(layers "F.Cu" "B.Cu")
		(net "FM_PVCCFA_EHV_FIVRA_CPU1_EN")
	)
	(via
		(at 106.63428 -395.188948)
		(size 0.508)
		(drill 0.254)
		(layers "F.Cu" "B.Cu")
		(net "FM_PVCCFA_EHV_FIVRA_CPU1_EN")
	)
	(via
		(at 231.06888 -202.910694)
		(size 0.508)
		(drill 0.254)
		(layers "F.Cu" "B.Cu")
		(net "FM_PVCCFA_EHV_FIVRA_CPU1_EN")
	)
	(via
		(at 101.825552 -354.459032)
		(size 0.508)
		(drill 0.254)
		(layers "F.Cu" "B.Cu")
		(net "FM_PVCCFA_EHV_FIVRA_CPU1_EN")
	)
	(segment
		(start 159.962088 -123.916948)
		(end 159.82188 -123.77674)
		(width 0.12954)
		(layer "B.Cu")
		(net "FM_PVCCFA_EHV_FIVRA_CPU1_EN")
	)
	(segment
		(start 160.43783 -123.916948)
		(end 159.962088 -123.916948)
		(width 0.12954)
		(layer "B.Cu")
		(net "FM_PVCCFA_EHV_FIVRA_CPU1_EN")
	)
	(segment
		(start 159.82188 -126.639828)
		(end 159.82188 -123.77674)
		(width 0.127)
		(layer "In4.Cu")
		(net "FM_PVCCFA_EHV_FIVRA_CPU1_EN")
	)
	(segment
		(start 195.45046 -129.819908)
		(end 192.406016 -129.819908)
		(width 0.127)
		(layer "In4.Cu")
		(net "FM_PVCCFA_EHV_FIVRA_CPU1_EN")
	)
	(segment
		(start 170.48988 -129.250948)
		(end 167.54094 -129.250948)
		(width 0.127)
		(layer "In4.Cu")
		(net "FM_PVCCFA_EHV_FIVRA_CPU1_EN")
	)
	(segment
		(start 162.87496 -129.692908)
		(end 159.82188 -126.639828)
		(width 0.127)
		(layer "In4.Cu")
		(net "FM_PVCCFA_EHV_FIVRA_CPU1_EN")
	)
	(segment
		(start 221.791276 -247.748298)
		(end 229.030276 -240.509298)
		(width 0.127)
		(layer "In4.Cu")
		(net "FM_PVCCFA_EHV_FIVRA_CPU1_EN")
	)
	(segment
		(start 184.715912 -126.482348)
		(end 184.124092 -127.074168)
		(width 0.127)
		(layer "In4.Cu")
		(net "FM_PVCCFA_EHV_FIVRA_CPU1_EN")
	)
	(segment
		(start 167.09898 -129.692908)
		(end 162.87496 -129.692908)
		(width 0.127)
		(layer "In4.Cu")
		(net "FM_PVCCFA_EHV_FIVRA_CPU1_EN")
	)
	(segment
		(start 183.564784 -378.092716)
		(end 189.848744 -378.092716)
		(width 0.127)
		(layer "In4.Cu")
		(net "FM_PVCCFA_EHV_FIVRA_CPU1_EN")
	)
	(segment
		(start 196.47662 -128.793748)
		(end 195.45046 -129.819908)
		(width 0.127)
		(layer "In4.Cu")
		(net "FM_PVCCFA_EHV_FIVRA_CPU1_EN")
	)
	(segment
		(start 174.811436 -386.846064)
		(end 183.564784 -378.092716)
		(width 0.127)
		(layer "In4.Cu")
		(net "FM_PVCCFA_EHV_FIVRA_CPU1_EN")
	)
	(segment
		(start 174.44212 -128.638808)
		(end 171.10202 -128.638808)
		(width 0.127)
		(layer "In4.Cu")
		(net "FM_PVCCFA_EHV_FIVRA_CPU1_EN")
	)
	(segment
		(start 175.235362 -127.34036)
		(end 174.87392 -127.701802)
		(width 0.127)
		(layer "In4.Cu")
		(net "FM_PVCCFA_EHV_FIVRA_CPU1_EN")
	)
	(segment
		(start 174.87392 -128.207008)
		(end 174.44212 -128.638808)
		(width 0.127)
		(layer "In4.Cu")
		(net "FM_PVCCFA_EHV_FIVRA_CPU1_EN")
	)
	(segment
		(start 192.406016 -129.819908)
		(end 189.068456 -126.482348)
		(width 0.127)
		(layer "In4.Cu")
		(net "FM_PVCCFA_EHV_FIVRA_CPU1_EN")
	)
	(segment
		(start 179.885848 -127.34036)
		(end 175.235362 -127.34036)
		(width 0.127)
		(layer "In4.Cu")
		(net "FM_PVCCFA_EHV_FIVRA_CPU1_EN")
	)
	(segment
		(start 171.10202 -128.638808)
		(end 170.48988 -129.250948)
		(width 0.127)
		(layer "In4.Cu")
		(net "FM_PVCCFA_EHV_FIVRA_CPU1_EN")
	)
	(segment
		(start 215.58123 -348.192344)
		(end 221.791276 -341.982298)
		(width 0.127)
		(layer "In4.Cu")
		(net "FM_PVCCFA_EHV_FIVRA_CPU1_EN")
	)
	(segment
		(start 211.67217 -348.192344)
		(end 215.58123 -348.192344)
		(width 0.127)
		(layer "In4.Cu")
		(net "FM_PVCCFA_EHV_FIVRA_CPU1_EN")
	)
	(segment
		(start 197.907656 -370.033804)
		(end 197.907656 -361.956858)
		(width 0.127)
		(layer "In4.Cu")
		(net "FM_PVCCFA_EHV_FIVRA_CPU1_EN")
	)
	(segment
		(start 221.791276 -341.982298)
		(end 221.791276 -247.748298)
		(width 0.127)
		(layer "In4.Cu")
		(net "FM_PVCCFA_EHV_FIVRA_CPU1_EN")
	)
	(segment
		(start 184.124092 -127.074168)
		(end 180.15204 -127.074168)
		(width 0.127)
		(layer "In4.Cu")
		(net "FM_PVCCFA_EHV_FIVRA_CPU1_EN")
	)
	(segment
		(start 189.848744 -378.092716)
		(end 197.907656 -370.033804)
		(width 0.127)
		(layer "In4.Cu")
		(net "FM_PVCCFA_EHV_FIVRA_CPU1_EN")
	)
	(segment
		(start 180.15204 -127.074168)
		(end 179.885848 -127.34036)
		(width 0.127)
		(layer "In4.Cu")
		(net "FM_PVCCFA_EHV_FIVRA_CPU1_EN")
	)
	(segment
		(start 174.811436 -394.191744)
		(end 174.811436 -386.846064)
		(width 0.127)
		(layer "In4.Cu")
		(net "FM_PVCCFA_EHV_FIVRA_CPU1_EN")
	)
	(segment
		(start 174.017432 -394.985748)
		(end 174.811436 -394.191744)
		(width 0.127)
		(layer "In4.Cu")
		(net "FM_PVCCFA_EHV_FIVRA_CPU1_EN")
	)
	(segment
		(start 197.907656 -361.956858)
		(end 211.67217 -348.192344)
		(width 0.127)
		(layer "In4.Cu")
		(net "FM_PVCCFA_EHV_FIVRA_CPU1_EN")
	)
	(segment
		(start 167.54094 -129.250948)
		(end 167.09898 -129.692908)
		(width 0.127)
		(layer "In4.Cu")
		(net "FM_PVCCFA_EHV_FIVRA_CPU1_EN")
	)
	(segment
		(start 229.030276 -204.949298)
		(end 231.06888 -202.910694)
		(width 0.127)
		(layer "In4.Cu")
		(net "FM_PVCCFA_EHV_FIVRA_CPU1_EN")
	)
	(segment
		(start 173.71822 -394.985748)
		(end 174.017432 -394.985748)
		(width 0.127)
		(layer "In4.Cu")
		(net "FM_PVCCFA_EHV_FIVRA_CPU1_EN")
	)
	(segment
		(start 189.068456 -126.482348)
		(end 184.715912 -126.482348)
		(width 0.127)
		(layer "In4.Cu")
		(net "FM_PVCCFA_EHV_FIVRA_CPU1_EN")
	)
	(segment
		(start 229.030276 -240.509298)
		(end 229.030276 -204.949298)
		(width 0.127)
		(layer "In4.Cu")
		(net "FM_PVCCFA_EHV_FIVRA_CPU1_EN")
	)
	(segment
		(start 174.87392 -127.701802)
		(end 174.87392 -128.207008)
		(width 0.127)
		(layer "In4.Cu")
		(net "FM_PVCCFA_EHV_FIVRA_CPU1_EN")
	)
	(segment
		(start 208.58988 -150.205948)
		(end 209.60588 -150.205948)
		(width 0.127)
		(layer "In11.Cu")
		(net "FM_PVCCFA_EHV_FIVRA_CPU1_EN")
	)
	(segment
		(start 209.98688 -152.395428)
		(end 211.15528 -153.563828)
		(width 0.127)
		(layer "In11.Cu")
		(net "FM_PVCCFA_EHV_FIVRA_CPU1_EN")
	)
	(segment
		(start 211.15528 -153.563828)
		(end 211.15528 -159.574738)
		(width 0.127)
		(layer "In11.Cu")
		(net "FM_PVCCFA_EHV_FIVRA_CPU1_EN")
	)
	(segment
		(start 209.98688 -150.586948)
		(end 209.98688 -152.395428)
		(width 0.127)
		(layer "In11.Cu")
		(net "FM_PVCCFA_EHV_FIVRA_CPU1_EN")
	)
	(segment
		(start 196.47662 -129.15265)
		(end 196.90588 -129.58191)
		(width 0.127)
		(layer "In11.Cu")
		(net "FM_PVCCFA_EHV_FIVRA_CPU1_EN")
	)
	(segment
		(start 223.497394 -171.916852)
		(end 223.497394 -196.481954)
		(width 0.127)
		(layer "In11.Cu")
		(net "FM_PVCCFA_EHV_FIVRA_CPU1_EN")
	)
	(segment
		(start 108.52658 -395.188948)
		(end 106.63428 -395.188948)
		(width 0.127)
		(layer "In11.Cu")
		(net "FM_PVCCFA_EHV_FIVRA_CPU1_EN")
	)
	(segment
		(start 209.60588 -150.205948)
		(end 209.98688 -150.586948)
		(width 0.127)
		(layer "In11.Cu")
		(net "FM_PVCCFA_EHV_FIVRA_CPU1_EN")
	)
	(segment
		(start 196.90588 -129.58191)
		(end 196.90588 -133.568948)
		(width 0.127)
		(layer "In11.Cu")
		(net "FM_PVCCFA_EHV_FIVRA_CPU1_EN")
	)
	(segment
		(start 198.30288 -134.965948)
		(end 198.30288 -137.886948)
		(width 0.127)
		(layer "In11.Cu")
		(net "FM_PVCCFA_EHV_FIVRA_CPU1_EN")
	)
	(segment
		(start 171.18838 -394.985748)
		(end 170.561508 -395.61262)
		(width 0.127)
		(layer "In11.Cu")
		(net "FM_PVCCFA_EHV_FIVRA_CPU1_EN")
	)
	(segment
		(start 170.561508 -395.61262)
		(end 167.59428 -395.61262)
		(width 0.127)
		(layer "In11.Cu")
		(net "FM_PVCCFA_EHV_FIVRA_CPU1_EN")
	)
	(segment
		(start 198.30288 -137.886948)
		(end 206.43088 -146.014948)
		(width 0.127)
		(layer "In11.Cu")
		(net "FM_PVCCFA_EHV_FIVRA_CPU1_EN")
	)
	(segment
		(start 229.926134 -202.910694)
		(end 231.06888 -202.910694)
		(width 0.127)
		(layer "In11.Cu")
		(net "FM_PVCCFA_EHV_FIVRA_CPU1_EN")
	)
	(segment
		(start 166.611808 -394.630148)
		(end 109.08538 -394.630148)
		(width 0.127)
		(layer "In11.Cu")
		(net "FM_PVCCFA_EHV_FIVRA_CPU1_EN")
	)
	(segment
		(start 196.47662 -128.793748)
		(end 196.47662 -129.15265)
		(width 0.127)
		(layer "In11.Cu")
		(net "FM_PVCCFA_EHV_FIVRA_CPU1_EN")
	)
	(segment
		(start 211.15528 -159.574738)
		(end 223.497394 -171.916852)
		(width 0.127)
		(layer "In11.Cu")
		(net "FM_PVCCFA_EHV_FIVRA_CPU1_EN")
	)
	(segment
		(start 223.497394 -196.481954)
		(end 229.926134 -202.910694)
		(width 0.127)
		(layer "In11.Cu")
		(net "FM_PVCCFA_EHV_FIVRA_CPU1_EN")
	)
	(segment
		(start 173.71822 -394.985748)
		(end 171.18838 -394.985748)
		(width 0.127)
		(layer "In11.Cu")
		(net "FM_PVCCFA_EHV_FIVRA_CPU1_EN")
	)
	(segment
		(start 206.43088 -146.014948)
		(end 206.68488 -146.014948)
		(width 0.127)
		(layer "In11.Cu")
		(net "FM_PVCCFA_EHV_FIVRA_CPU1_EN")
	)
	(segment
		(start 207.70088 -149.316948)
		(end 208.58988 -150.205948)
		(width 0.127)
		(layer "In11.Cu")
		(net "FM_PVCCFA_EHV_FIVRA_CPU1_EN")
	)
	(segment
		(start 109.08538 -394.630148)
		(end 108.52658 -395.188948)
		(width 0.127)
		(layer "In11.Cu")
		(net "FM_PVCCFA_EHV_FIVRA_CPU1_EN")
	)
	(segment
		(start 167.59428 -395.61262)
		(end 166.611808 -394.630148)
		(width 0.127)
		(layer "In11.Cu")
		(net "FM_PVCCFA_EHV_FIVRA_CPU1_EN")
	)
	(segment
		(start 207.70088 -147.030948)
		(end 207.70088 -149.316948)
		(width 0.127)
		(layer "In11.Cu")
		(net "FM_PVCCFA_EHV_FIVRA_CPU1_EN")
	)
	(segment
		(start 196.90588 -133.568948)
		(end 198.30288 -134.965948)
		(width 0.127)
		(layer "In11.Cu")
		(net "FM_PVCCFA_EHV_FIVRA_CPU1_EN")
	)
	(segment
		(start 206.68488 -146.014948)
		(end 207.70088 -147.030948)
		(width 0.127)
		(layer "In11.Cu")
		(net "FM_PVCCFA_EHV_FIVRA_CPU1_EN")
	)
	(segment
		(start 100.63988 -362.981748)
		(end 100.63988 -355.644704)
		(width 0.127)
		(layer "In15.Cu")
		(net "FM_PVCCFA_EHV_FIVRA_CPU1_EN")
	)
	(segment
		(start 106.63428 -395.188948)
		(end 106.63428 -393.868148)
		(width 0.127)
		(layer "In15.Cu")
		(net "FM_PVCCFA_EHV_FIVRA_CPU1_EN")
	)
	(segment
		(start 103.28148 -390.515348)
		(end 103.28148 -365.623348)
		(width 0.127)
		(layer "In15.Cu")
		(net "FM_PVCCFA_EHV_FIVRA_CPU1_EN")
	)
	(segment
		(start 106.63428 -393.868148)
		(end 103.28148 -390.515348)
		(width 0.127)
		(layer "In15.Cu")
		(net "FM_PVCCFA_EHV_FIVRA_CPU1_EN")
	)
	(segment
		(start 103.28148 -365.623348)
		(end 100.63988 -362.981748)
		(width 0.127)
		(layer "In15.Cu")
		(net "FM_PVCCFA_EHV_FIVRA_CPU1_EN")
	)
	(segment
		(start 100.63988 -355.644704)
		(end 101.825552 -354.459032)
		(width 0.127)
		(layer "In15.Cu")
		(net "FM_PVCCFA_EHV_FIVRA_CPU1_EN")
	)
	(segment
		(start 171.88688 -122.79122)
		(end 171.88688 -125.364748)
		(width 0.12954)
		(layer "F.Cu")
		(net "FM_PVCCFA_EHV_FIVRA_CPU0_R_EN")
	)
	(segment
		(start 171.88688 -125.364748)
		(end 171.50588 -125.745748)
		(width 0.12954)
		(layer "F.Cu")
		(net "FM_PVCCFA_EHV_FIVRA_CPU0_R_EN")
	)
	(segment
		(start 170.23588 -126.564898)
		(end 171.50588 -126.564898)
		(width 0.12954)
		(layer "F.Cu")
		(net "FM_PVCCFA_EHV_FIVRA_CPU0_R_EN")
	)
	(segment
		(start 172.555662 -122.122438)
		(end 171.88688 -122.79122)
		(width 0.12954)
		(layer "F.Cu")
		(net "FM_PVCCFA_EHV_FIVRA_CPU0_R_EN")
	)
	(segment
		(start 171.50588 -125.745748)
		(end 171.50588 -126.564898)
		(width 0.12954)
		(layer "F.Cu")
		(net "FM_PVCCFA_EHV_FIVRA_CPU0_R_EN")
	)
	(segment
		(start 172.555662 -121.775474)
		(end 172.555662 -122.122438)
		(width 0.12954)
		(layer "F.Cu")
		(net "FM_PVCCFA_EHV_FIVRA_CPU0_R_EN")
	)
	(via
		(at 171.88688 -125.364748)
		(size 0.762)
		(drill 0.381)
		(layers "F.Cu" "B.Cu")
		(net "FM_PVCCFA_EHV_FIVRA_CPU0_R_EN")
	)
	(segment
		(start 170.23588 -127.364998)
		(end 170.23588 -127.974598)
		(width 0.12954)
		(layer "F.Cu")
		(net "FM_PVCCFA_EHV_FIVRA_CPU0_EN")
	)
	(segment
		(start 351.116138 -354.083112)
		(end 349.771716 -354.083112)
		(width 0.12954)
		(layer "F.Cu")
		(net "FM_PVCCFA_EHV_FIVRA_CPU0_EN")
	)
	(via
		(at 170.23588 -127.974598)
		(size 0.508)
		(drill 0.254)
		(layers "F.Cu" "B.Cu")
		(net "FM_PVCCFA_EHV_FIVRA_CPU0_EN")
	)
	(via
		(at 242.429538 -201.10069)
		(size 0.508)
		(drill 0.254)
		(layers "F.Cu" "B.Cu")
		(net "FM_PVCCFA_EHV_FIVRA_CPU0_EN")
	)
	(via
		(at 349.771716 -354.083112)
		(size 0.508)
		(drill 0.254)
		(layers "F.Cu" "B.Cu")
		(net "FM_PVCCFA_EHV_FIVRA_CPU0_EN")
	)
	(via
		(at 301.70882 -386.635752)
		(size 0.508)
		(drill 0.254)
		(layers "F.Cu" "B.Cu")
		(net "FM_PVCCFA_EHV_FIVRA_CPU0_EN")
	)
	(via
		(at 211.51088 -125.694948)
		(size 0.508)
		(drill 0.254)
		(layers "F.Cu" "B.Cu")
		(net "FM_PVCCFA_EHV_FIVRA_CPU0_EN")
	)
	(segment
		(start 189.20714 -126.009908)
		(end 184.577482 -126.009908)
		(width 0.127)
		(layer "In4.Cu")
		(net "FM_PVCCFA_EHV_FIVRA_CPU0_EN")
	)
	(segment
		(start 211.51088 -125.694948)
		(end 211.51088 -125.415548)
		(width 0.127)
		(layer "In4.Cu")
		(net "FM_PVCCFA_EHV_FIVRA_CPU0_EN")
	)
	(segment
		(start 200.37806 -127.216408)
		(end 199.34428 -128.250188)
		(width 0.127)
		(layer "In4.Cu")
		(net "FM_PVCCFA_EHV_FIVRA_CPU0_EN")
	)
	(segment
		(start 210.12404 -125.186948)
		(end 208.915 -126.395988)
		(width 0.127)
		(layer "In4.Cu")
		(net "FM_PVCCFA_EHV_FIVRA_CPU0_EN")
	)
	(segment
		(start 290.292282 -382.107948)
		(end 297.181016 -382.107948)
		(width 0.127)
		(layer "In4.Cu")
		(net "FM_PVCCFA_EHV_FIVRA_CPU0_EN")
	)
	(segment
		(start 252.45568 -278.833834)
		(end 249.99188 -281.297634)
		(width 0.127)
		(layer "In4.Cu")
		(net "FM_PVCCFA_EHV_FIVRA_CPU0_EN")
	)
	(segment
		(start 196.28866 -128.250188)
		(end 195.43268 -129.106168)
		(width 0.127)
		(layer "In4.Cu")
		(net "FM_PVCCFA_EHV_FIVRA_CPU0_EN")
	)
	(segment
		(start 242.429538 -201.10069)
		(end 252.45568 -211.126832)
		(width 0.127)
		(layer "In4.Cu")
		(net "FM_PVCCFA_EHV_FIVRA_CPU0_EN")
	)
	(segment
		(start 281.59456 -357.548942)
		(end 281.59456 -373.410226)
		(width 0.127)
		(layer "In4.Cu")
		(net "FM_PVCCFA_EHV_FIVRA_CPU0_EN")
	)
	(segment
		(start 205.6892 -126.395988)
		(end 204.86878 -127.216408)
		(width 0.127)
		(layer "In4.Cu")
		(net "FM_PVCCFA_EHV_FIVRA_CPU0_EN")
	)
	(segment
		(start 179.93614 -126.642368)
		(end 179.669948 -126.90856)
		(width 0.127)
		(layer "In4.Cu")
		(net "FM_PVCCFA_EHV_FIVRA_CPU0_EN")
	)
	(segment
		(start 199.34428 -128.250188)
		(end 196.28866 -128.250188)
		(width 0.127)
		(layer "In4.Cu")
		(net "FM_PVCCFA_EHV_FIVRA_CPU0_EN")
	)
	(segment
		(start 192.3034 -129.106168)
		(end 189.20714 -126.009908)
		(width 0.127)
		(layer "In4.Cu")
		(net "FM_PVCCFA_EHV_FIVRA_CPU0_EN")
	)
	(segment
		(start 281.59456 -373.410226)
		(end 290.292282 -382.107948)
		(width 0.127)
		(layer "In4.Cu")
		(net "FM_PVCCFA_EHV_FIVRA_CPU0_EN")
	)
	(segment
		(start 184.577482 -126.009908)
		(end 183.945022 -126.642368)
		(width 0.127)
		(layer "In4.Cu")
		(net "FM_PVCCFA_EHV_FIVRA_CPU0_EN")
	)
	(segment
		(start 175.056292 -126.90856)
		(end 174.471584 -127.493268)
		(width 0.127)
		(layer "In4.Cu")
		(net "FM_PVCCFA_EHV_FIVRA_CPU0_EN")
	)
	(segment
		(start 179.669948 -126.90856)
		(end 175.056292 -126.90856)
		(width 0.127)
		(layer "In4.Cu")
		(net "FM_PVCCFA_EHV_FIVRA_CPU0_EN")
	)
	(segment
		(start 252.45568 -211.126832)
		(end 252.45568 -278.833834)
		(width 0.127)
		(layer "In4.Cu")
		(net "FM_PVCCFA_EHV_FIVRA_CPU0_EN")
	)
	(segment
		(start 174.471584 -127.493268)
		(end 170.71721 -127.493268)
		(width 0.127)
		(layer "In4.Cu")
		(net "FM_PVCCFA_EHV_FIVRA_CPU0_EN")
	)
	(segment
		(start 204.86878 -127.216408)
		(end 200.37806 -127.216408)
		(width 0.127)
		(layer "In4.Cu")
		(net "FM_PVCCFA_EHV_FIVRA_CPU0_EN")
	)
	(segment
		(start 170.71721 -127.493268)
		(end 170.23588 -127.974598)
		(width 0.127)
		(layer "In4.Cu")
		(net "FM_PVCCFA_EHV_FIVRA_CPU0_EN")
	)
	(segment
		(start 297.181016 -382.107948)
		(end 301.70882 -386.635752)
		(width 0.127)
		(layer "In4.Cu")
		(net "FM_PVCCFA_EHV_FIVRA_CPU0_EN")
	)
	(segment
		(start 183.945022 -126.642368)
		(end 179.93614 -126.642368)
		(width 0.127)
		(layer "In4.Cu")
		(net "FM_PVCCFA_EHV_FIVRA_CPU0_EN")
	)
	(segment
		(start 208.915 -126.395988)
		(end 205.6892 -126.395988)
		(width 0.127)
		(layer "In4.Cu")
		(net "FM_PVCCFA_EHV_FIVRA_CPU0_EN")
	)
	(segment
		(start 195.43268 -129.106168)
		(end 192.3034 -129.106168)
		(width 0.127)
		(layer "In4.Cu")
		(net "FM_PVCCFA_EHV_FIVRA_CPU0_EN")
	)
	(segment
		(start 211.51088 -125.415548)
		(end 211.28228 -125.186948)
		(width 0.127)
		(layer "In4.Cu")
		(net "FM_PVCCFA_EHV_FIVRA_CPU0_EN")
	)
	(segment
		(start 249.99188 -325.946262)
		(end 281.59456 -357.548942)
		(width 0.127)
		(layer "In4.Cu")
		(net "FM_PVCCFA_EHV_FIVRA_CPU0_EN")
	)
	(segment
		(start 211.28228 -125.186948)
		(end 210.12404 -125.186948)
		(width 0.127)
		(layer "In4.Cu")
		(net "FM_PVCCFA_EHV_FIVRA_CPU0_EN")
	)
	(segment
		(start 249.99188 -281.297634)
		(end 249.99188 -325.946262)
		(width 0.127)
		(layer "In4.Cu")
		(net "FM_PVCCFA_EHV_FIVRA_CPU0_EN")
	)
	(segment
		(start 348.58452 -371.249448)
		(end 346.079572 -373.754396)
		(width 0.127)
		(layer "In6.Cu")
		(net "FM_PVCCFA_EHV_FIVRA_CPU0_EN")
	)
	(segment
		(start 348.58452 -367.292128)
		(end 348.58452 -371.249448)
		(width 0.127)
		(layer "In6.Cu")
		(net "FM_PVCCFA_EHV_FIVRA_CPU0_EN")
	)
	(segment
		(start 345.3511 -364.058708)
		(end 348.58452 -367.292128)
		(width 0.127)
		(layer "In6.Cu")
		(net "FM_PVCCFA_EHV_FIVRA_CPU0_EN")
	)
	(segment
		(start 317.854076 -386.635752)
		(end 301.70882 -386.635752)
		(width 0.127)
		(layer "In6.Cu")
		(net "FM_PVCCFA_EHV_FIVRA_CPU0_EN")
	)
	(segment
		(start 330.735432 -373.754396)
		(end 317.854076 -386.635752)
		(width 0.127)
		(layer "In6.Cu")
		(net "FM_PVCCFA_EHV_FIVRA_CPU0_EN")
	)
	(segment
		(start 349.771716 -354.083112)
		(end 347.460316 -354.083112)
		(width 0.127)
		(layer "In6.Cu")
		(net "FM_PVCCFA_EHV_FIVRA_CPU0_EN")
	)
	(segment
		(start 346.48648 -355.056948)
		(end 346.48648 -360.594148)
		(width 0.127)
		(layer "In6.Cu")
		(net "FM_PVCCFA_EHV_FIVRA_CPU0_EN")
	)
	(segment
		(start 345.3511 -361.729528)
		(end 345.3511 -364.058708)
		(width 0.127)
		(layer "In6.Cu")
		(net "FM_PVCCFA_EHV_FIVRA_CPU0_EN")
	)
	(segment
		(start 346.079572 -373.754396)
		(end 330.735432 -373.754396)
		(width 0.127)
		(layer "In6.Cu")
		(net "FM_PVCCFA_EHV_FIVRA_CPU0_EN")
	)
	(segment
		(start 347.460316 -354.083112)
		(end 346.48648 -355.056948)
		(width 0.127)
		(layer "In6.Cu")
		(net "FM_PVCCFA_EHV_FIVRA_CPU0_EN")
	)
	(segment
		(start 346.48648 -360.594148)
		(end 345.3511 -361.729528)
		(width 0.127)
		(layer "In6.Cu")
		(net "FM_PVCCFA_EHV_FIVRA_CPU0_EN")
	)
	(segment
		(start 221.436946 -157.70098)
		(end 221.436946 -145.894806)
		(width 0.127)
		(layer "In11.Cu")
		(net "FM_PVCCFA_EHV_FIVRA_CPU0_EN")
	)
	(segment
		(start 244.22608 -180.490114)
		(end 221.436946 -157.70098)
		(width 0.127)
		(layer "In11.Cu")
		(net "FM_PVCCFA_EHV_FIVRA_CPU0_EN")
	)
	(segment
		(start 244.22608 -199.304148)
		(end 244.22608 -180.490114)
		(width 0.127)
		(layer "In11.Cu")
		(net "FM_PVCCFA_EHV_FIVRA_CPU0_EN")
	)
	(segment
		(start 211.51088 -128.107948)
		(end 211.51088 -125.694948)
		(width 0.127)
		(layer "In11.Cu")
		(net "FM_PVCCFA_EHV_FIVRA_CPU0_EN")
	)
	(segment
		(start 221.436946 -145.894806)
		(end 212.57006 -137.02792)
		(width 0.127)
		(layer "In11.Cu")
		(net "FM_PVCCFA_EHV_FIVRA_CPU0_EN")
	)
	(segment
		(start 242.429538 -201.10069)
		(end 244.22608 -199.304148)
		(width 0.127)
		(layer "In11.Cu")
		(net "FM_PVCCFA_EHV_FIVRA_CPU0_EN")
	)
	(segment
		(start 212.57006 -129.167128)
		(end 211.51088 -128.107948)
		(width 0.127)
		(layer "In11.Cu")
		(net "FM_PVCCFA_EHV_FIVRA_CPU0_EN")
	)
	(segment
		(start 212.57006 -137.02792)
		(end 212.57006 -129.167128)
		(width 0.127)
		(layer "In11.Cu")
		(net "FM_PVCCFA_EHV_FIVRA_CPU0_EN")
	)
	(segment
		(start 174.955708 -116.975382)
		(end 174.555658 -117.375432)
		(width 0.12954)
		(layer "F.Cu")
		(net "FM_PVCCFA_EHV_CPU1_R_EN")
	)
	(via
		(at 168.275 -118.62562)
		(size 0.6604)
		(drill 0.3302)
		(layers "F.Cu" "B.Cu")
		(net "FM_PVCCFA_EHV_CPU1_R_EN")
	)
	(via
		(at 174.555658 -117.375432)
		(size 0.4572)
		(drill 0.254)
		(layers "F.Cu" "B.Cu")
		(net "FM_PVCCFA_EHV_CPU1_R_EN")
	)
	(segment
		(start 161.472626 -118.151148)
		(end 161.23793 -118.385844)
		(width 0.12954)
		(layer "B.Cu")
		(net "FM_PVCCFA_EHV_CPU1_R_EN")
	)
	(segment
		(start 165.04793 -118.836948)
		(end 165.536626 -118.836948)
		(width 0.12954)
		(layer "B.Cu")
		(net "FM_PVCCFA_EHV_CPU1_R_EN")
	)
	(segment
		(start 165.04793 -118.526052)
		(end 164.673026 -118.151148)
		(width 0.12954)
		(layer "B.Cu")
		(net "FM_PVCCFA_EHV_CPU1_R_EN")
	)
	(segment
		(start 165.04793 -118.836948)
		(end 165.04793 -118.526052)
		(width 0.12954)
		(layer "B.Cu")
		(net "FM_PVCCFA_EHV_CPU1_R_EN")
	)
	(segment
		(start 168.275 -118.62562)
		(end 168.48836 -118.62562)
		(width 0.12954)
		(layer "B.Cu")
		(net "FM_PVCCFA_EHV_CPU1_R_EN")
	)
	(segment
		(start 164.673026 -118.151148)
		(end 161.472626 -118.151148)
		(width 0.12954)
		(layer "B.Cu")
		(net "FM_PVCCFA_EHV_CPU1_R_EN")
	)
	(segment
		(start 169.333672 -117.780308)
		(end 174.150782 -117.780308)
		(width 0.12954)
		(layer "B.Cu")
		(net "FM_PVCCFA_EHV_CPU1_R_EN")
	)
	(segment
		(start 174.150782 -117.780308)
		(end 174.555658 -117.375432)
		(width 0.12954)
		(layer "B.Cu")
		(net "FM_PVCCFA_EHV_CPU1_R_EN")
	)
	(segment
		(start 168.48836 -118.62562)
		(end 169.333672 -117.780308)
		(width 0.12954)
		(layer "B.Cu")
		(net "FM_PVCCFA_EHV_CPU1_R_EN")
	)
	(segment
		(start 167.504872 -119.395748)
		(end 168.275 -118.62562)
		(width 0.12954)
		(layer "B.Cu")
		(net "FM_PVCCFA_EHV_CPU1_R_EN")
	)
	(segment
		(start 166.095426 -119.395748)
		(end 167.504872 -119.395748)
		(width 0.12954)
		(layer "B.Cu")
		(net "FM_PVCCFA_EHV_CPU1_R_EN")
	)
	(segment
		(start 165.536626 -118.836948)
		(end 166.095426 -119.395748)
		(width 0.12954)
		(layer "B.Cu")
		(net "FM_PVCCFA_EHV_CPU1_R_EN")
	)
	(segment
		(start 161.23793 -118.385844)
		(end 161.23793 -118.836948)
		(width 0.12954)
		(layer "B.Cu")
		(net "FM_PVCCFA_EHV_CPU1_R_EN")
	)
	(segment
		(start 38.426136 -133.81482)
		(end 37.356288 -133.81482)
		(width 0.12954)
		(layer "F.Cu")
		(net "FM_PVCCFA_EHV_CPU1_EN")
	)
	(segment
		(start 38.450012 -133.838696)
		(end 38.426136 -133.81482)
		(width 0.12954)
		(layer "F.Cu")
		(net "FM_PVCCFA_EHV_CPU1_EN")
	)
	(via
		(at 139.3317 -122.017028)
		(size 0.508)
		(drill 0.254)
		(layers "F.Cu" "B.Cu")
		(net "FM_PVCCFA_EHV_CPU1_EN")
	)
	(via
		(at 38.450012 -133.838696)
		(size 0.508)
		(drill 0.254)
		(layers "F.Cu" "B.Cu")
		(net "FM_PVCCFA_EHV_CPU1_EN")
	)
	(via
		(at 159.10306 -118.842028)
		(size 0.508)
		(drill 0.254)
		(layers "F.Cu" "B.Cu")
		(net "FM_PVCCFA_EHV_CPU1_EN")
	)
	(segment
		(start 159.73298 -119.471948)
		(end 160.279334 -119.471948)
		(width 0.12954)
		(layer "B.Cu")
		(net "FM_PVCCFA_EHV_CPU1_EN")
	)
	(segment
		(start 160.43783 -119.313452)
		(end 160.43783 -118.836948)
		(width 0.12954)
		(layer "B.Cu")
		(net "FM_PVCCFA_EHV_CPU1_EN")
	)
	(segment
		(start 160.279334 -119.471948)
		(end 160.43783 -119.313452)
		(width 0.12954)
		(layer "B.Cu")
		(net "FM_PVCCFA_EHV_CPU1_EN")
	)
	(segment
		(start 159.10306 -118.842028)
		(end 159.73298 -119.471948)
		(width 0.12954)
		(layer "B.Cu")
		(net "FM_PVCCFA_EHV_CPU1_EN")
	)
	(segment
		(start 139.1285 -122.017028)
		(end 139.3317 -122.017028)
		(width 0.127)
		(layer "In6.Cu")
		(net "FM_PVCCFA_EHV_CPU1_EN")
	)
	(segment
		(start 159.10306 -118.842028)
		(end 158.62554 -119.319548)
		(width 0.127)
		(layer "In6.Cu")
		(net "FM_PVCCFA_EHV_CPU1_EN")
	)
	(segment
		(start 158.62554 -119.319548)
		(end 151.844248 -119.319548)
		(width 0.127)
		(layer "In6.Cu")
		(net "FM_PVCCFA_EHV_CPU1_EN")
	)
	(segment
		(start 151.844248 -119.319548)
		(end 150.7871 -118.2624)
		(width 0.127)
		(layer "In6.Cu")
		(net "FM_PVCCFA_EHV_CPU1_EN")
	)
	(segment
		(start 147.09902 -119.154448)
		(end 139.6873 -119.154448)
		(width 0.127)
		(layer "In6.Cu")
		(net "FM_PVCCFA_EHV_CPU1_EN")
	)
	(segment
		(start 138.4046 -121.293128)
		(end 139.1285 -122.017028)
		(width 0.127)
		(layer "In6.Cu")
		(net "FM_PVCCFA_EHV_CPU1_EN")
	)
	(segment
		(start 147.991068 -118.2624)
		(end 147.09902 -119.154448)
		(width 0.127)
		(layer "In6.Cu")
		(net "FM_PVCCFA_EHV_CPU1_EN")
	)
	(segment
		(start 150.7871 -118.2624)
		(end 147.991068 -118.2624)
		(width 0.127)
		(layer "In6.Cu")
		(net "FM_PVCCFA_EHV_CPU1_EN")
	)
	(segment
		(start 138.4046 -120.437148)
		(end 138.4046 -121.293128)
		(width 0.127)
		(layer "In6.Cu")
		(net "FM_PVCCFA_EHV_CPU1_EN")
	)
	(segment
		(start 139.6873 -119.154448)
		(end 138.4046 -120.437148)
		(width 0.127)
		(layer "In6.Cu")
		(net "FM_PVCCFA_EHV_CPU1_EN")
	)
	(segment
		(start 139.3317 -122.017028)
		(end 138.820144 -121.505472)
		(width 0.127)
		(layer "In13.Cu")
		(net "FM_PVCCFA_EHV_CPU1_EN")
	)
	(segment
		(start 42.93362 -131.313428)
		(end 40.408352 -133.838696)
		(width 0.127)
		(layer "In13.Cu")
		(net "FM_PVCCFA_EHV_CPU1_EN")
	)
	(segment
		(start 111.141764 -119.425212)
		(end 106.008424 -124.558552)
		(width 0.127)
		(layer "In13.Cu")
		(net "FM_PVCCFA_EHV_CPU1_EN")
	)
	(segment
		(start 40.408352 -133.838696)
		(end 38.450012 -133.838696)
		(width 0.127)
		(layer "In13.Cu")
		(net "FM_PVCCFA_EHV_CPU1_EN")
	)
	(segment
		(start 44.812712 -124.558552)
		(end 42.93362 -126.437644)
		(width 0.127)
		(layer "In13.Cu")
		(net "FM_PVCCFA_EHV_CPU1_EN")
	)
	(segment
		(start 132.832856 -121.505472)
		(end 130.752596 -119.425212)
		(width 0.127)
		(layer "In13.Cu")
		(net "FM_PVCCFA_EHV_CPU1_EN")
	)
	(segment
		(start 138.820144 -121.505472)
		(end 132.832856 -121.505472)
		(width 0.127)
		(layer "In13.Cu")
		(net "FM_PVCCFA_EHV_CPU1_EN")
	)
	(segment
		(start 106.008424 -124.558552)
		(end 44.812712 -124.558552)
		(width 0.127)
		(layer "In13.Cu")
		(net "FM_PVCCFA_EHV_CPU1_EN")
	)
	(segment
		(start 42.93362 -126.437644)
		(end 42.93362 -131.313428)
		(width 0.127)
		(layer "In13.Cu")
		(net "FM_PVCCFA_EHV_CPU1_EN")
	)
	(segment
		(start 130.752596 -119.425212)
		(end 111.141764 -119.425212)
		(width 0.127)
		(layer "In13.Cu")
		(net "FM_PVCCFA_EHV_CPU1_EN")
	)
	(segment
		(start 157.42793 -118.436644)
		(end 157.42793 -118.836948)
		(width 0.12954)
		(layer "F.Cu")
		(net "FM_PVCCFA_EHV_CPU0_R_EN")
	)
	(segment
		(start 158.61284 -118.176548)
		(end 157.688026 -118.176548)
		(width 0.12954)
		(layer "F.Cu")
		(net "FM_PVCCFA_EHV_CPU0_R_EN")
	)
	(segment
		(start 161.85388 -118.836948)
		(end 161.23793 -118.836948)
		(width 0.12954)
		(layer "F.Cu")
		(net "FM_PVCCFA_EHV_CPU0_R_EN")
	)
	(segment
		(start 161.23793 -118.475252)
		(end 160.939226 -118.176548)
		(width 0.12954)
		(layer "F.Cu")
		(net "FM_PVCCFA_EHV_CPU0_R_EN")
	)
	(segment
		(start 157.688026 -118.176548)
		(end 157.42793 -118.436644)
		(width 0.12954)
		(layer "F.Cu")
		(net "FM_PVCCFA_EHV_CPU0_R_EN")
	)
	(segment
		(start 161.23793 -118.836948)
		(end 161.23793 -118.475252)
		(width 0.12954)
		(layer "F.Cu")
		(net "FM_PVCCFA_EHV_CPU0_R_EN")
	)
	(segment
		(start 160.939226 -118.176548)
		(end 158.61284 -118.176548)
		(width 0.12954)
		(layer "F.Cu")
		(net "FM_PVCCFA_EHV_CPU0_R_EN")
	)
	(segment
		(start 174.155608 -117.775482)
		(end 173.755558 -118.175532)
		(width 0.12954)
		(layer "F.Cu")
		(net "FM_PVCCFA_EHV_CPU0_R_EN")
	)
	(via
		(at 158.61284 -118.176548)
		(size 0.762)
		(drill 0.381)
		(layers "F.Cu" "B.Cu")
		(net "FM_PVCCFA_EHV_CPU0_R_EN")
	)
	(via
		(at 161.85388 -118.836948)
		(size 0.508)
		(drill 0.254)
		(layers "F.Cu" "B.Cu")
		(net "FM_PVCCFA_EHV_CPU0_R_EN")
	)
	(via
		(at 173.755558 -118.175532)
		(size 0.4572)
		(drill 0.254)
		(layers "F.Cu" "B.Cu")
		(net "FM_PVCCFA_EHV_CPU0_R_EN")
	)
	(segment
		(start 173.23308 -119.375682)
		(end 171.697142 -119.375682)
		(width 0.127)
		(layer "In6.Cu")
		(net "FM_PVCCFA_EHV_CPU0_R_EN")
	)
	(segment
		(start 171.503848 -119.182388)
		(end 170.474132 -119.182388)
		(width 0.127)
		(layer "In6.Cu")
		(net "FM_PVCCFA_EHV_CPU0_R_EN")
	)
	(segment
		(start 165.843712 -120.09628)
		(end 165.19144 -119.444008)
		(width 0.127)
		(layer "In6.Cu")
		(net "FM_PVCCFA_EHV_CPU0_R_EN")
	)
	(segment
		(start 173.35119 -118.5799)
		(end 173.35119 -119.257572)
		(width 0.127)
		(layer "In6.Cu")
		(net "FM_PVCCFA_EHV_CPU0_R_EN")
	)
	(segment
		(start 169.56024 -120.09628)
		(end 165.843712 -120.09628)
		(width 0.127)
		(layer "In6.Cu")
		(net "FM_PVCCFA_EHV_CPU0_R_EN")
	)
	(segment
		(start 170.474132 -119.182388)
		(end 169.56024 -120.09628)
		(width 0.127)
		(layer "In6.Cu")
		(net "FM_PVCCFA_EHV_CPU0_R_EN")
	)
	(segment
		(start 173.755558 -118.175532)
		(end 173.35119 -118.5799)
		(width 0.127)
		(layer "In6.Cu")
		(net "FM_PVCCFA_EHV_CPU0_R_EN")
	)
	(segment
		(start 173.35119 -119.257572)
		(end 173.23308 -119.375682)
		(width 0.127)
		(layer "In6.Cu")
		(net "FM_PVCCFA_EHV_CPU0_R_EN")
	)
	(segment
		(start 165.19144 -119.444008)
		(end 162.46094 -119.444008)
		(width 0.127)
		(layer "In6.Cu")
		(net "FM_PVCCFA_EHV_CPU0_R_EN")
	)
	(segment
		(start 171.697142 -119.375682)
		(end 171.503848 -119.182388)
		(width 0.127)
		(layer "In6.Cu")
		(net "FM_PVCCFA_EHV_CPU0_R_EN")
	)
	(segment
		(start 162.46094 -119.444008)
		(end 161.85388 -118.836948)
		(width 0.127)
		(layer "In6.Cu")
		(net "FM_PVCCFA_EHV_CPU0_R_EN")
	)
	(segment
		(start 431.573178 -141.168882)
		(end 431.000154 -140.595858)
		(width 0.12954)
		(layer "F.Cu")
		(net "FM_PVCCFA_EHV_CPU0_EN")
	)
	(segment
		(start 156.62783 -118.836948)
		(end 156.01188 -118.836948)
		(width 0.12954)
		(layer "F.Cu")
		(net "FM_PVCCFA_EHV_CPU0_EN")
	)
	(via
		(at 431.573178 -141.168882)
		(size 0.508)
		(drill 0.254)
		(layers "F.Cu" "B.Cu")
		(net "FM_PVCCFA_EHV_CPU0_EN")
	)
	(via
		(at 156.01188 -118.836948)
		(size 0.508)
		(drill 0.254)
		(layers "F.Cu" "B.Cu")
		(net "FM_PVCCFA_EHV_CPU0_EN")
	)
	(segment
		(start 416.43935 -122.240548)
		(end 252.86081 -122.240548)
		(width 0.127)
		(layer "In13.Cu")
		(net "FM_PVCCFA_EHV_CPU0_EN")
	)
	(segment
		(start 431.573178 -141.168882)
		(end 430.71288 -140.308584)
		(width 0.127)
		(layer "In13.Cu")
		(net "FM_PVCCFA_EHV_CPU0_EN")
	)
	(segment
		(start 154.67838 -121.02338)
		(end 154.67838 -119.528336)
		(width 0.127)
		(layer "In13.Cu")
		(net "FM_PVCCFA_EHV_CPU0_EN")
	)
	(segment
		(start 166.07282 -123.193048)
		(end 165.34892 -123.916948)
		(width 0.127)
		(layer "In13.Cu")
		(net "FM_PVCCFA_EHV_CPU0_EN")
	)
	(segment
		(start 440.267852 -113.248948)
		(end 425.43095 -113.248948)
		(width 0.127)
		(layer "In13.Cu")
		(net "FM_PVCCFA_EHV_CPU0_EN")
	)
	(segment
		(start 209.8167 -120.6373)
		(end 206.8195 -120.6373)
		(width 0.127)
		(layer "In13.Cu")
		(net "FM_PVCCFA_EHV_CPU0_EN")
	)
	(segment
		(start 177.57648 -123.434348)
		(end 174.96028 -123.434348)
		(width 0.127)
		(layer "In13.Cu")
		(net "FM_PVCCFA_EHV_CPU0_EN")
	)
	(segment
		(start 205.800452 -121.656348)
		(end 195.82765 -121.656348)
		(width 0.127)
		(layer "In13.Cu")
		(net "FM_PVCCFA_EHV_CPU0_EN")
	)
	(segment
		(start 211.9376 -118.5164)
		(end 209.8167 -120.6373)
		(width 0.127)
		(layer "In13.Cu")
		(net "FM_PVCCFA_EHV_CPU0_EN")
	)
	(segment
		(start 159.055308 -123.193048)
		(end 158.41726 -122.555)
		(width 0.127)
		(layer "In13.Cu")
		(net "FM_PVCCFA_EHV_CPU0_EN")
	)
	(segment
		(start 160.43783 -123.193048)
		(end 159.055308 -123.193048)
		(width 0.127)
		(layer "In13.Cu")
		(net "FM_PVCCFA_EHV_CPU0_EN")
	)
	(segment
		(start 243.17833 -116.413788)
		(end 240.49101 -113.726468)
		(width 0.127)
		(layer "In13.Cu")
		(net "FM_PVCCFA_EHV_CPU0_EN")
	)
	(segment
		(start 218.919298 -118.5164)
		(end 211.9376 -118.5164)
		(width 0.127)
		(layer "In13.Cu")
		(net "FM_PVCCFA_EHV_CPU0_EN")
	)
	(segment
		(start 206.8195 -120.6373)
		(end 205.800452 -121.656348)
		(width 0.127)
		(layer "In13.Cu")
		(net "FM_PVCCFA_EHV_CPU0_EN")
	)
	(segment
		(start 178.38928 -122.621548)
		(end 177.57648 -123.434348)
		(width 0.127)
		(layer "In13.Cu")
		(net "FM_PVCCFA_EHV_CPU0_EN")
	)
	(segment
		(start 158.41726 -122.555)
		(end 156.21 -122.555)
		(width 0.127)
		(layer "In13.Cu")
		(net "FM_PVCCFA_EHV_CPU0_EN")
	)
	(segment
		(start 247.03405 -116.413788)
		(end 243.17833 -116.413788)
		(width 0.127)
		(layer "In13.Cu")
		(net "FM_PVCCFA_EHV_CPU0_EN")
	)
	(segment
		(start 433.38115 -133.008878)
		(end 438.42178 -127.968248)
		(width 0.127)
		(layer "In13.Cu")
		(net "FM_PVCCFA_EHV_CPU0_EN")
	)
	(segment
		(start 195.12915 -122.354848)
		(end 189.29858 -122.354848)
		(width 0.127)
		(layer "In13.Cu")
		(net "FM_PVCCFA_EHV_CPU0_EN")
	)
	(segment
		(start 445.08928 -118.070376)
		(end 440.267852 -113.248948)
		(width 0.127)
		(layer "In13.Cu")
		(net "FM_PVCCFA_EHV_CPU0_EN")
	)
	(segment
		(start 189.29858 -122.354848)
		(end 188.58738 -123.066048)
		(width 0.127)
		(layer "In13.Cu")
		(net "FM_PVCCFA_EHV_CPU0_EN")
	)
	(segment
		(start 445.08928 -126.13386)
		(end 445.08928 -118.070376)
		(width 0.127)
		(layer "In13.Cu")
		(net "FM_PVCCFA_EHV_CPU0_EN")
	)
	(segment
		(start 156.21 -122.555)
		(end 154.67838 -121.02338)
		(width 0.127)
		(layer "In13.Cu")
		(net "FM_PVCCFA_EHV_CPU0_EN")
	)
	(segment
		(start 223.70923 -113.726468)
		(end 218.919298 -118.5164)
		(width 0.127)
		(layer "In13.Cu")
		(net "FM_PVCCFA_EHV_CPU0_EN")
	)
	(segment
		(start 155.369768 -118.836948)
		(end 156.01188 -118.836948)
		(width 0.127)
		(layer "In13.Cu")
		(net "FM_PVCCFA_EHV_CPU0_EN")
	)
	(segment
		(start 183.87568 -122.621548)
		(end 178.38928 -122.621548)
		(width 0.127)
		(layer "In13.Cu")
		(net "FM_PVCCFA_EHV_CPU0_EN")
	)
	(segment
		(start 425.43095 -113.248948)
		(end 416.43935 -122.240548)
		(width 0.127)
		(layer "In13.Cu")
		(net "FM_PVCCFA_EHV_CPU0_EN")
	)
	(segment
		(start 161.16173 -123.916948)
		(end 160.43783 -123.193048)
		(width 0.127)
		(layer "In13.Cu")
		(net "FM_PVCCFA_EHV_CPU0_EN")
	)
	(segment
		(start 165.34892 -123.916948)
		(end 161.16173 -123.916948)
		(width 0.127)
		(layer "In13.Cu")
		(net "FM_PVCCFA_EHV_CPU0_EN")
	)
	(segment
		(start 184.32018 -123.066048)
		(end 183.87568 -122.621548)
		(width 0.127)
		(layer "In13.Cu")
		(net "FM_PVCCFA_EHV_CPU0_EN")
	)
	(segment
		(start 240.49101 -113.726468)
		(end 223.70923 -113.726468)
		(width 0.127)
		(layer "In13.Cu")
		(net "FM_PVCCFA_EHV_CPU0_EN")
	)
	(segment
		(start 168.97858 -123.193048)
		(end 166.07282 -123.193048)
		(width 0.127)
		(layer "In13.Cu")
		(net "FM_PVCCFA_EHV_CPU0_EN")
	)
	(segment
		(start 188.58738 -123.066048)
		(end 184.32018 -123.066048)
		(width 0.127)
		(layer "In13.Cu")
		(net "FM_PVCCFA_EHV_CPU0_EN")
	)
	(segment
		(start 174.71898 -123.193048)
		(end 172.605192 -123.193048)
		(width 0.127)
		(layer "In13.Cu")
		(net "FM_PVCCFA_EHV_CPU0_EN")
	)
	(segment
		(start 154.67838 -119.528336)
		(end 155.369768 -118.836948)
		(width 0.127)
		(layer "In13.Cu")
		(net "FM_PVCCFA_EHV_CPU0_EN")
	)
	(segment
		(start 174.96028 -123.434348)
		(end 174.71898 -123.193048)
		(width 0.127)
		(layer "In13.Cu")
		(net "FM_PVCCFA_EHV_CPU0_EN")
	)
	(segment
		(start 172.605192 -123.193048)
		(end 172.09262 -123.70562)
		(width 0.127)
		(layer "In13.Cu")
		(net "FM_PVCCFA_EHV_CPU0_EN")
	)
	(segment
		(start 430.71288 -133.467348)
		(end 431.17135 -133.008878)
		(width 0.127)
		(layer "In13.Cu")
		(net "FM_PVCCFA_EHV_CPU0_EN")
	)
	(segment
		(start 443.254892 -127.968248)
		(end 445.08928 -126.13386)
		(width 0.127)
		(layer "In13.Cu")
		(net "FM_PVCCFA_EHV_CPU0_EN")
	)
	(segment
		(start 431.17135 -133.008878)
		(end 433.38115 -133.008878)
		(width 0.127)
		(layer "In13.Cu")
		(net "FM_PVCCFA_EHV_CPU0_EN")
	)
	(segment
		(start 172.09262 -123.70562)
		(end 169.491152 -123.70562)
		(width 0.127)
		(layer "In13.Cu")
		(net "FM_PVCCFA_EHV_CPU0_EN")
	)
	(segment
		(start 195.82765 -121.656348)
		(end 195.12915 -122.354848)
		(width 0.127)
		(layer "In13.Cu")
		(net "FM_PVCCFA_EHV_CPU0_EN")
	)
	(segment
		(start 430.71288 -140.308584)
		(end 430.71288 -133.467348)
		(width 0.127)
		(layer "In13.Cu")
		(net "FM_PVCCFA_EHV_CPU0_EN")
	)
	(segment
		(start 169.491152 -123.70562)
		(end 168.97858 -123.193048)
		(width 0.127)
		(layer "In13.Cu")
		(net "FM_PVCCFA_EHV_CPU0_EN")
	)
	(segment
		(start 252.86081 -122.240548)
		(end 247.03405 -116.413788)
		(width 0.127)
		(layer "In13.Cu")
		(net "FM_PVCCFA_EHV_CPU0_EN")
	)
	(segment
		(start 438.42178 -127.968248)
		(end 443.254892 -127.968248)
		(width 0.127)
		(layer "In13.Cu")
		(net "FM_PVCCFA_EHV_CPU0_EN")
	)
	(segment
		(start 171.355512 -122.565668)
		(end 171.355512 -122.937524)
		(width 0.12954)
		(layer "F.Cu")
		(net "FM_PVCCD_HV_CPU1_EN")
	)
	(segment
		(start 171.755562 -122.165618)
		(end 171.355512 -122.565668)
		(width 0.12954)
		(layer "F.Cu")
		(net "FM_PVCCD_HV_CPU1_EN")
	)
	(segment
		(start 171.755562 -121.775474)
		(end 171.755562 -122.165618)
		(width 0.12954)
		(layer "F.Cu")
		(net "FM_PVCCD_HV_CPU1_EN")
	)
	(via
		(at 148.3614 -121.399808)
		(size 0.508)
		(drill 0.254)
		(layers "F.Cu" "B.Cu")
		(net "FM_PVCCD_HV_CPU1_EN")
	)
	(via
		(at 20.381214 -167.388794)
		(size 0.508)
		(drill 0.254)
		(layers "F.Cu" "B.Cu")
		(net "FM_PVCCD_HV_CPU1_EN")
	)
	(via
		(at 171.355512 -122.937524)
		(size 0.4572)
		(drill 0.254)
		(layers "F.Cu" "B.Cu")
		(net "FM_PVCCD_HV_CPU1_EN")
	)
	(segment
		(start 170.836336 -121.656348)
		(end 166.527226 -121.656348)
		(width 0.12954)
		(layer "B.Cu")
		(net "FM_PVCCD_HV_CPU1_EN")
	)
	(segment
		(start 171.355512 -122.937524)
		(end 171.355512 -122.175524)
		(width 0.12954)
		(layer "B.Cu")
		(net "FM_PVCCD_HV_CPU1_EN")
	)
	(segment
		(start 20.944078 -167.698674)
		(end 21.093938 -167.548814)
		(width 0.12954)
		(layer "B.Cu")
		(net "FM_PVCCD_HV_CPU1_EN")
	)
	(segment
		(start 171.355512 -122.175524)
		(end 170.836336 -121.656348)
		(width 0.12954)
		(layer "B.Cu")
		(net "FM_PVCCD_HV_CPU1_EN")
	)
	(segment
		(start 21.093938 -167.548814)
		(end 21.514562 -167.548814)
		(width 0.12954)
		(layer "B.Cu")
		(net "FM_PVCCD_HV_CPU1_EN")
	)
	(segment
		(start 166.527226 -121.656348)
		(end 165.536626 -122.646948)
		(width 0.12954)
		(layer "B.Cu")
		(net "FM_PVCCD_HV_CPU1_EN")
	)
	(segment
		(start 20.691094 -167.698674)
		(end 20.944078 -167.698674)
		(width 0.12954)
		(layer "B.Cu")
		(net "FM_PVCCD_HV_CPU1_EN")
	)
	(segment
		(start 165.536626 -122.646948)
		(end 165.04793 -122.646948)
		(width 0.12954)
		(layer "B.Cu")
		(net "FM_PVCCD_HV_CPU1_EN")
	)
	(segment
		(start 20.381214 -167.388794)
		(end 20.691094 -167.698674)
		(width 0.12954)
		(layer "B.Cu")
		(net "FM_PVCCD_HV_CPU1_EN")
	)
	(segment
		(start 166.491412 -125.405388)
		(end 150.510748 -125.405388)
		(width 0.127)
		(layer "In6.Cu")
		(net "FM_PVCCD_HV_CPU1_EN")
	)
	(segment
		(start 168.91508 -122.98172)
		(end 166.491412 -125.405388)
		(width 0.127)
		(layer "In6.Cu")
		(net "FM_PVCCD_HV_CPU1_EN")
	)
	(segment
		(start 171.355512 -122.937524)
		(end 171.311316 -122.98172)
		(width 0.127)
		(layer "In6.Cu")
		(net "FM_PVCCD_HV_CPU1_EN")
	)
	(segment
		(start 171.311316 -122.98172)
		(end 168.91508 -122.98172)
		(width 0.127)
		(layer "In6.Cu")
		(net "FM_PVCCD_HV_CPU1_EN")
	)
	(segment
		(start 148.3614 -123.25604)
		(end 148.3614 -121.399808)
		(width 0.127)
		(layer "In6.Cu")
		(net "FM_PVCCD_HV_CPU1_EN")
	)
	(segment
		(start 150.510748 -125.405388)
		(end 148.3614 -123.25604)
		(width 0.127)
		(layer "In6.Cu")
		(net "FM_PVCCD_HV_CPU1_EN")
	)
	(segment
		(start 21.374354 -167.388794)
		(end 20.381214 -167.388794)
		(width 0.127)
		(layer "In13.Cu")
		(net "FM_PVCCD_HV_CPU1_EN")
	)
	(segment
		(start 22.122892 -166.640256)
		(end 21.374354 -167.388794)
		(width 0.127)
		(layer "In13.Cu")
		(net "FM_PVCCD_HV_CPU1_EN")
	)
	(segment
		(start 137.87628 -117.262148)
		(end 137.258806 -116.644674)
		(width 0.127)
		(layer "In13.Cu")
		(net "FM_PVCCD_HV_CPU1_EN")
	)
	(segment
		(start 127.81788 -115.738148)
		(end 127.23368 -116.322348)
		(width 0.127)
		(layer "In13.Cu")
		(net "FM_PVCCD_HV_CPU1_EN")
	)
	(segment
		(start 95.00108 -120.005348)
		(end 49.8856 -120.005348)
		(width 0.127)
		(layer "In13.Cu")
		(net "FM_PVCCD_HV_CPU1_EN")
	)
	(segment
		(start 24.67737 -118.941088)
		(end 17.33042 -126.288038)
		(width 0.127)
		(layer "In13.Cu")
		(net "FM_PVCCD_HV_CPU1_EN")
	)
	(segment
		(start 148.3614 -121.399808)
		(end 144.48536 -121.399808)
		(width 0.127)
		(layer "In13.Cu")
		(net "FM_PVCCD_HV_CPU1_EN")
	)
	(segment
		(start 140.3477 -117.262148)
		(end 137.87628 -117.262148)
		(width 0.127)
		(layer "In13.Cu")
		(net "FM_PVCCD_HV_CPU1_EN")
	)
	(segment
		(start 137.258806 -116.644674)
		(end 132.542026 -116.644674)
		(width 0.127)
		(layer "In13.Cu")
		(net "FM_PVCCD_HV_CPU1_EN")
	)
	(segment
		(start 17.33042 -126.288038)
		(end 17.33042 -152.423114)
		(width 0.127)
		(layer "In13.Cu")
		(net "FM_PVCCD_HV_CPU1_EN")
	)
	(segment
		(start 131.2164 -116.296948)
		(end 130.6576 -115.738148)
		(width 0.127)
		(layer "In13.Cu")
		(net "FM_PVCCD_HV_CPU1_EN")
	)
	(segment
		(start 48.82134 -118.941088)
		(end 24.67737 -118.941088)
		(width 0.127)
		(layer "In13.Cu")
		(net "FM_PVCCD_HV_CPU1_EN")
	)
	(segment
		(start 23.7363 -161.946844)
		(end 22.122892 -163.560252)
		(width 0.127)
		(layer "In13.Cu")
		(net "FM_PVCCD_HV_CPU1_EN")
	)
	(segment
		(start 22.122892 -163.560252)
		(end 22.122892 -166.640256)
		(width 0.127)
		(layer "In13.Cu")
		(net "FM_PVCCD_HV_CPU1_EN")
	)
	(segment
		(start 49.8856 -120.005348)
		(end 48.82134 -118.941088)
		(width 0.127)
		(layer "In13.Cu")
		(net "FM_PVCCD_HV_CPU1_EN")
	)
	(segment
		(start 96.04248 -118.963948)
		(end 95.00108 -120.005348)
		(width 0.127)
		(layer "In13.Cu")
		(net "FM_PVCCD_HV_CPU1_EN")
	)
	(segment
		(start 23.7363 -158.828994)
		(end 23.7363 -161.946844)
		(width 0.127)
		(layer "In13.Cu")
		(net "FM_PVCCD_HV_CPU1_EN")
	)
	(segment
		(start 106.3752 -116.322348)
		(end 103.7336 -118.963948)
		(width 0.127)
		(layer "In13.Cu")
		(net "FM_PVCCD_HV_CPU1_EN")
	)
	(segment
		(start 17.33042 -152.423114)
		(end 23.7363 -158.828994)
		(width 0.127)
		(layer "In13.Cu")
		(net "FM_PVCCD_HV_CPU1_EN")
	)
	(segment
		(start 130.6576 -115.738148)
		(end 127.81788 -115.738148)
		(width 0.127)
		(layer "In13.Cu")
		(net "FM_PVCCD_HV_CPU1_EN")
	)
	(segment
		(start 132.542026 -116.644674)
		(end 132.1943 -116.296948)
		(width 0.127)
		(layer "In13.Cu")
		(net "FM_PVCCD_HV_CPU1_EN")
	)
	(segment
		(start 144.48536 -121.399808)
		(end 140.3477 -117.262148)
		(width 0.127)
		(layer "In13.Cu")
		(net "FM_PVCCD_HV_CPU1_EN")
	)
	(segment
		(start 103.7336 -118.963948)
		(end 96.04248 -118.963948)
		(width 0.127)
		(layer "In13.Cu")
		(net "FM_PVCCD_HV_CPU1_EN")
	)
	(segment
		(start 132.1943 -116.296948)
		(end 131.2164 -116.296948)
		(width 0.127)
		(layer "In13.Cu")
		(net "FM_PVCCD_HV_CPU1_EN")
	)
	(segment
		(start 127.23368 -116.322348)
		(end 106.3752 -116.322348)
		(width 0.127)
		(layer "In13.Cu")
		(net "FM_PVCCD_HV_CPU1_EN")
	)
	(segment
		(start 171.755562 -121.220738)
		(end 171.755562 -120.975374)
		(width 0.12954)
		(layer "F.Cu")
		(net "FM_PVCCD_HV_CPU0_EN")
	)
	(segment
		(start 168.402 -124.333)
		(end 166.37 -124.333)
		(width 0.12954)
		(layer "F.Cu")
		(net "FM_PVCCD_HV_CPU0_EN")
	)
	(segment
		(start 170.321732 -123.08586)
		(end 171.34586 -122.061732)
		(width 0.12954)
		(layer "F.Cu")
		(net "FM_PVCCD_HV_CPU0_EN")
	)
	(segment
		(start 166.37 -124.333)
		(end 165.04793 -123.01093)
		(width 0.12954)
		(layer "F.Cu")
		(net "FM_PVCCD_HV_CPU0_EN")
	)
	(segment
		(start 165.04793 -122.646948)
		(end 165.25748 -122.646948)
		(width 0.12954)
		(layer "F.Cu")
		(net "FM_PVCCD_HV_CPU0_EN")
	)
	(segment
		(start 167.401748 -122.392948)
		(end 168.09466 -123.08586)
		(width 0.12954)
		(layer "F.Cu")
		(net "FM_PVCCD_HV_CPU0_EN")
	)
	(segment
		(start 165.51148 -122.392948)
		(end 166.497 -122.392948)
		(width 0.12954)
		(layer "F.Cu")
		(net "FM_PVCCD_HV_CPU0_EN")
	)
	(segment
		(start 168.09466 -123.08586)
		(end 170.321732 -123.08586)
		(width 0.12954)
		(layer "F.Cu")
		(net "FM_PVCCD_HV_CPU0_EN")
	)
	(segment
		(start 166.497 -122.392948)
		(end 167.401748 -122.392948)
		(width 0.12954)
		(layer "F.Cu")
		(net "FM_PVCCD_HV_CPU0_EN")
	)
	(segment
		(start 165.25748 -122.646948)
		(end 165.51148 -122.392948)
		(width 0.12954)
		(layer "F.Cu")
		(net "FM_PVCCD_HV_CPU0_EN")
	)
	(segment
		(start 171.34586 -121.63044)
		(end 171.755562 -121.220738)
		(width 0.12954)
		(layer "F.Cu")
		(net "FM_PVCCD_HV_CPU0_EN")
	)
	(segment
		(start 165.04793 -123.01093)
		(end 165.04793 -122.646948)
		(width 0.12954)
		(layer "F.Cu")
		(net "FM_PVCCD_HV_CPU0_EN")
	)
	(segment
		(start 171.34586 -122.061732)
		(end 171.34586 -121.63044)
		(width 0.12954)
		(layer "F.Cu")
		(net "FM_PVCCD_HV_CPU0_EN")
	)
	(via
		(at 166.497 -122.392948)
		(size 0.762)
		(drill 0.381)
		(layers "F.Cu" "B.Cu")
		(net "FM_PVCCD_HV_CPU0_EN")
	)
	(via
		(at 441.786264 -122.158506)
		(size 0.508)
		(drill 0.254)
		(layers "F.Cu" "B.Cu")
		(net "FM_PVCCD_HV_CPU0_EN")
	)
	(via
		(at 168.402 -124.333)
		(size 0.508)
		(drill 0.254)
		(layers "F.Cu" "B.Cu")
		(net "FM_PVCCD_HV_CPU0_EN")
	)
	(segment
		(start 437.792368 -121.730008)
		(end 437.371744 -121.730008)
		(width 0.12954)
		(layer "B.Cu")
		(net "FM_PVCCD_HV_CPU0_EN")
	)
	(segment
		(start 438.220866 -122.158506)
		(end 437.792368 -121.730008)
		(width 0.12954)
		(layer "B.Cu")
		(net "FM_PVCCD_HV_CPU0_EN")
	)
	(segment
		(start 441.786264 -122.158506)
		(end 438.220866 -122.158506)
		(width 0.12954)
		(layer "B.Cu")
		(net "FM_PVCCD_HV_CPU0_EN")
	)
	(segment
		(start 192.79108 -124.170948)
		(end 193.37528 -124.755148)
		(width 0.127)
		(layer "In13.Cu")
		(net "FM_PVCCD_HV_CPU0_EN")
	)
	(segment
		(start 246.67591 -117.277388)
		(end 252.50267 -123.104148)
		(width 0.127)
		(layer "In13.Cu")
		(net "FM_PVCCD_HV_CPU0_EN")
	)
	(segment
		(start 174.26178 -124.488448)
		(end 176.653952 -124.488448)
		(width 0.127)
		(layer "In13.Cu")
		(net "FM_PVCCD_HV_CPU0_EN")
	)
	(segment
		(start 177.835052 -125.669548)
		(end 180.114956 -125.669548)
		(width 0.127)
		(layer "In13.Cu")
		(net "FM_PVCCD_HV_CPU0_EN")
	)
	(segment
		(start 186.08548 -124.170948)
		(end 192.79108 -124.170948)
		(width 0.127)
		(layer "In13.Cu")
		(net "FM_PVCCD_HV_CPU0_EN")
	)
	(segment
		(start 252.50267 -123.104148)
		(end 416.79749 -123.104148)
		(width 0.127)
		(layer "In13.Cu")
		(net "FM_PVCCD_HV_CPU0_EN")
	)
	(segment
		(start 180.114956 -125.669548)
		(end 181.029356 -124.755148)
		(width 0.127)
		(layer "In13.Cu")
		(net "FM_PVCCD_HV_CPU0_EN")
	)
	(segment
		(start 173.93158 -124.158248)
		(end 174.26178 -124.488448)
		(width 0.127)
		(layer "In13.Cu")
		(net "FM_PVCCD_HV_CPU0_EN")
	)
	(segment
		(start 185.50128 -124.755148)
		(end 186.08548 -124.170948)
		(width 0.127)
		(layer "In13.Cu")
		(net "FM_PVCCD_HV_CPU0_EN")
	)
	(segment
		(start 168.87444 -124.80544)
		(end 172.54474 -124.80544)
		(width 0.127)
		(layer "In13.Cu")
		(net "FM_PVCCD_HV_CPU0_EN")
	)
	(segment
		(start 181.029356 -124.755148)
		(end 185.50128 -124.755148)
		(width 0.127)
		(layer "In13.Cu")
		(net "FM_PVCCD_HV_CPU0_EN")
	)
	(segment
		(start 209.585052 -122.519948)
		(end 212.598 -119.507)
		(width 0.127)
		(layer "In13.Cu")
		(net "FM_PVCCD_HV_CPU0_EN")
	)
	(segment
		(start 212.598 -119.507)
		(end 219.150438 -119.507)
		(width 0.127)
		(layer "In13.Cu")
		(net "FM_PVCCD_HV_CPU0_EN")
	)
	(segment
		(start 200.37933 -124.755148)
		(end 202.61453 -122.519948)
		(width 0.127)
		(layer "In13.Cu")
		(net "FM_PVCCD_HV_CPU0_EN")
	)
	(segment
		(start 416.79749 -123.104148)
		(end 425.78909 -114.112548)
		(width 0.127)
		(layer "In13.Cu")
		(net "FM_PVCCD_HV_CPU0_EN")
	)
	(segment
		(start 193.37528 -124.755148)
		(end 200.37933 -124.755148)
		(width 0.127)
		(layer "In13.Cu")
		(net "FM_PVCCD_HV_CPU0_EN")
	)
	(segment
		(start 240.13287 -114.590068)
		(end 242.82019 -117.277388)
		(width 0.127)
		(layer "In13.Cu")
		(net "FM_PVCCD_HV_CPU0_EN")
	)
	(segment
		(start 224.06737 -114.590068)
		(end 240.13287 -114.590068)
		(width 0.127)
		(layer "In13.Cu")
		(net "FM_PVCCD_HV_CPU0_EN")
	)
	(segment
		(start 176.653952 -124.488448)
		(end 177.835052 -125.669548)
		(width 0.127)
		(layer "In13.Cu")
		(net "FM_PVCCD_HV_CPU0_EN")
	)
	(segment
		(start 172.54474 -124.80544)
		(end 173.191932 -124.158248)
		(width 0.127)
		(layer "In13.Cu")
		(net "FM_PVCCD_HV_CPU0_EN")
	)
	(segment
		(start 168.402 -124.333)
		(end 168.87444 -124.80544)
		(width 0.127)
		(layer "In13.Cu")
		(net "FM_PVCCD_HV_CPU0_EN")
	)
	(segment
		(start 441.786264 -115.989608)
		(end 441.786264 -122.158506)
		(width 0.127)
		(layer "In13.Cu")
		(net "FM_PVCCD_HV_CPU0_EN")
	)
	(segment
		(start 219.150438 -119.507)
		(end 224.06737 -114.590068)
		(width 0.127)
		(layer "In13.Cu")
		(net "FM_PVCCD_HV_CPU0_EN")
	)
	(segment
		(start 439.909204 -114.112548)
		(end 441.786264 -115.989608)
		(width 0.127)
		(layer "In13.Cu")
		(net "FM_PVCCD_HV_CPU0_EN")
	)
	(segment
		(start 425.78909 -114.112548)
		(end 439.909204 -114.112548)
		(width 0.127)
		(layer "In13.Cu")
		(net "FM_PVCCD_HV_CPU0_EN")
	)
	(segment
		(start 202.61453 -122.519948)
		(end 209.585052 -122.519948)
		(width 0.127)
		(layer "In13.Cu")
		(net "FM_PVCCD_HV_CPU0_EN")
	)
	(segment
		(start 242.82019 -117.277388)
		(end 246.67591 -117.277388)
		(width 0.127)
		(layer "In13.Cu")
		(net "FM_PVCCD_HV_CPU0_EN")
	)
	(segment
		(start 173.191932 -124.158248)
		(end 173.93158 -124.158248)
		(width 0.127)
		(layer "In13.Cu")
		(net "FM_PVCCD_HV_CPU0_EN")
	)
	(segment
		(start 183.755538 -111.375444)
		(end 184.155588 -110.975394)
		(width 0.12954)
		(layer "F.Cu")
		(net "FM_PS_PWROK_DLY_SEL")
	)
	(via
		(at 184.155588 -110.975394)
		(size 0.4572)
		(drill 0.254)
		(layers "F.Cu" "B.Cu")
		(net "FM_PS_PWROK_DLY_SEL")
	)
	(via
		(at 342.54694 -21.516848)
		(size 0.508)
		(drill 0.254)
		(layers "F.Cu" "B.Cu")
		(net "FM_PS_PWROK_DLY_SEL")
	)
	(via
		(at 330.53274 -111.978948)
		(size 0.508)
		(drill 0.254)
		(layers "F.Cu" "B.Cu")
		(net "FM_PS_PWROK_DLY_SEL")
	)
	(segment
		(start 343.39784 -21.435568)
		(end 344.12428 -22.162008)
		(width 0.12954)
		(layer "B.Cu")
		(net "FM_PS_PWROK_DLY_SEL")
	)
	(segment
		(start 344.12428 -27.783282)
		(end 341.672164 -30.235398)
		(width 0.12954)
		(layer "B.Cu")
		(net "FM_PS_PWROK_DLY_SEL")
	)
	(segment
		(start 344.12428 -22.162008)
		(end 344.12428 -27.783282)
		(width 0.12954)
		(layer "B.Cu")
		(net "FM_PS_PWROK_DLY_SEL")
	)
	(segment
		(start 342.62822 -21.435568)
		(end 343.39784 -21.435568)
		(width 0.12954)
		(layer "B.Cu")
		(net "FM_PS_PWROK_DLY_SEL")
	)
	(segment
		(start 341.672164 -30.235398)
		(end 341.672164 -30.636972)
		(width 0.12954)
		(layer "B.Cu")
		(net "FM_PS_PWROK_DLY_SEL")
	)
	(segment
		(start 342.54694 -21.516848)
		(end 342.62822 -21.435568)
		(width 0.12954)
		(layer "B.Cu")
		(net "FM_PS_PWROK_DLY_SEL")
	)
	(segment
		(start 342.4682 -21.516848)
		(end 342.54694 -21.516848)
		(width 0.127)
		(layer "In2.Cu")
		(net "FM_PS_PWROK_DLY_SEL")
	)
	(segment
		(start 340.54288 -27.912568)
		(end 340.54288 -23.442168)
		(width 0.127)
		(layer "In2.Cu")
		(net "FM_PS_PWROK_DLY_SEL")
	)
	(segment
		(start 333.215234 -51.269646)
		(end 334.113378 -51.269646)
		(width 0.127)
		(layer "In2.Cu")
		(net "FM_PS_PWROK_DLY_SEL")
	)
	(segment
		(start 334.97012 -39.705788)
		(end 334.97012 -39.169848)
		(width 0.127)
		(layer "In2.Cu")
		(net "FM_PS_PWROK_DLY_SEL")
	)
	(segment
		(start 338.96808 -29.487368)
		(end 340.54288 -27.912568)
		(width 0.127)
		(layer "In2.Cu")
		(net "FM_PS_PWROK_DLY_SEL")
	)
	(segment
		(start 334.113378 -51.269646)
		(end 335.29778 -50.085244)
		(width 0.127)
		(layer "In2.Cu")
		(net "FM_PS_PWROK_DLY_SEL")
	)
	(segment
		(start 335.5594 -40.295068)
		(end 334.97012 -39.705788)
		(width 0.127)
		(layer "In2.Cu")
		(net "FM_PS_PWROK_DLY_SEL")
	)
	(segment
		(start 330.904088 -72.42302)
		(end 330.904088 -62.885828)
		(width 0.127)
		(layer "In2.Cu")
		(net "FM_PS_PWROK_DLY_SEL")
	)
	(segment
		(start 333.022956 -53.641752)
		(end 333.284068 -53.38064)
		(width 0.127)
		(layer "In2.Cu")
		(net "FM_PS_PWROK_DLY_SEL")
	)
	(segment
		(start 333.19974 -56.109616)
		(end 333.19974 -55.676292)
		(width 0.127)
		(layer "In2.Cu")
		(net "FM_PS_PWROK_DLY_SEL")
	)
	(segment
		(start 333.284068 -57.90311)
		(end 333.284068 -56.851296)
		(width 0.127)
		(layer "In2.Cu")
		(net "FM_PS_PWROK_DLY_SEL")
	)
	(segment
		(start 333.022956 -55.499508)
		(end 333.022956 -53.641752)
		(width 0.127)
		(layer "In2.Cu")
		(net "FM_PS_PWROK_DLY_SEL")
	)
	(segment
		(start 333.284068 -56.851296)
		(end 333.015336 -56.582564)
		(width 0.127)
		(layer "In2.Cu")
		(net "FM_PS_PWROK_DLY_SEL")
	)
	(segment
		(start 333.015336 -56.582564)
		(end 333.015336 -56.29402)
		(width 0.127)
		(layer "In2.Cu")
		(net "FM_PS_PWROK_DLY_SEL")
	)
	(segment
		(start 330.53274 -111.978948)
		(end 330.43368 -111.879888)
		(width 0.127)
		(layer "In2.Cu")
		(net "FM_PS_PWROK_DLY_SEL")
	)
	(segment
		(start 330.00188 -73.325228)
		(end 330.904088 -72.42302)
		(width 0.127)
		(layer "In2.Cu")
		(net "FM_PS_PWROK_DLY_SEL")
	)
	(segment
		(start 335.98104 -48.768508)
		(end 335.98104 -42.581068)
		(width 0.127)
		(layer "In2.Cu")
		(net "FM_PS_PWROK_DLY_SEL")
	)
	(segment
		(start 330.43368 -111.879888)
		(end 330.43368 -74.559668)
		(width 0.127)
		(layer "In2.Cu")
		(net "FM_PS_PWROK_DLY_SEL")
	)
	(segment
		(start 333.046324 -51.438556)
		(end 333.215234 -51.269646)
		(width 0.127)
		(layer "In2.Cu")
		(net "FM_PS_PWROK_DLY_SEL")
	)
	(segment
		(start 333.284068 -52.774342)
		(end 333.046324 -52.536598)
		(width 0.127)
		(layer "In2.Cu")
		(net "FM_PS_PWROK_DLY_SEL")
	)
	(segment
		(start 330.904088 -62.885828)
		(end 331.69479 -62.095126)
		(width 0.127)
		(layer "In2.Cu")
		(net "FM_PS_PWROK_DLY_SEL")
	)
	(segment
		(start 335.5594 -42.159428)
		(end 335.5594 -40.295068)
		(width 0.127)
		(layer "In2.Cu")
		(net "FM_PS_PWROK_DLY_SEL")
	)
	(segment
		(start 335.29778 -49.451768)
		(end 335.98104 -48.768508)
		(width 0.127)
		(layer "In2.Cu")
		(net "FM_PS_PWROK_DLY_SEL")
	)
	(segment
		(start 333.284068 -53.38064)
		(end 333.284068 -52.774342)
		(width 0.127)
		(layer "In2.Cu")
		(net "FM_PS_PWROK_DLY_SEL")
	)
	(segment
		(start 331.69479 -59.492388)
		(end 333.284068 -57.90311)
		(width 0.127)
		(layer "In2.Cu")
		(net "FM_PS_PWROK_DLY_SEL")
	)
	(segment
		(start 333.015336 -56.29402)
		(end 333.19974 -56.109616)
		(width 0.127)
		(layer "In2.Cu")
		(net "FM_PS_PWROK_DLY_SEL")
	)
	(segment
		(start 335.98104 -42.581068)
		(end 335.5594 -42.159428)
		(width 0.127)
		(layer "In2.Cu")
		(net "FM_PS_PWROK_DLY_SEL")
	)
	(segment
		(start 335.29778 -50.085244)
		(end 335.29778 -49.451768)
		(width 0.127)
		(layer "In2.Cu")
		(net "FM_PS_PWROK_DLY_SEL")
	)
	(segment
		(start 333.19974 -55.676292)
		(end 333.022956 -55.499508)
		(width 0.127)
		(layer "In2.Cu")
		(net "FM_PS_PWROK_DLY_SEL")
	)
	(segment
		(start 331.69479 -62.095126)
		(end 331.69479 -59.492388)
		(width 0.127)
		(layer "In2.Cu")
		(net "FM_PS_PWROK_DLY_SEL")
	)
	(segment
		(start 330.00188 -74.127868)
		(end 330.00188 -73.325228)
		(width 0.127)
		(layer "In2.Cu")
		(net "FM_PS_PWROK_DLY_SEL")
	)
	(segment
		(start 333.046324 -52.536598)
		(end 333.046324 -51.438556)
		(width 0.127)
		(layer "In2.Cu")
		(net "FM_PS_PWROK_DLY_SEL")
	)
	(segment
		(start 334.97012 -39.169848)
		(end 338.96808 -35.171888)
		(width 0.127)
		(layer "In2.Cu")
		(net "FM_PS_PWROK_DLY_SEL")
	)
	(segment
		(start 340.54288 -23.442168)
		(end 342.4682 -21.516848)
		(width 0.127)
		(layer "In2.Cu")
		(net "FM_PS_PWROK_DLY_SEL")
	)
	(segment
		(start 338.96808 -35.171888)
		(end 338.96808 -29.487368)
		(width 0.127)
		(layer "In2.Cu")
		(net "FM_PS_PWROK_DLY_SEL")
	)
	(segment
		(start 330.43368 -74.559668)
		(end 330.00188 -74.127868)
		(width 0.127)
		(layer "In2.Cu")
		(net "FM_PS_PWROK_DLY_SEL")
	)
	(segment
		(start 211.48802 -104.239568)
		(end 216.22766 -104.239568)
		(width 0.127)
		(layer "In15.Cu")
		(net "FM_PS_PWROK_DLY_SEL")
	)
	(segment
		(start 211.249768 -104.47782)
		(end 211.48802 -104.239568)
		(width 0.127)
		(layer "In15.Cu")
		(net "FM_PS_PWROK_DLY_SEL")
	)
	(segment
		(start 206.920592 -106.873548)
		(end 209.31632 -104.47782)
		(width 0.127)
		(layer "In15.Cu")
		(net "FM_PS_PWROK_DLY_SEL")
	)
	(segment
		(start 219.93098 -104.638348)
		(end 232.292652 -104.638348)
		(width 0.127)
		(layer "In15.Cu")
		(net "FM_PS_PWROK_DLY_SEL")
	)
	(segment
		(start 186.8678 -110.333028)
		(end 189.077346 -110.333028)
		(width 0.127)
		(layer "In15.Cu")
		(net "FM_PS_PWROK_DLY_SEL")
	)
	(segment
		(start 209.31632 -104.47782)
		(end 211.249768 -104.47782)
		(width 0.127)
		(layer "In15.Cu")
		(net "FM_PS_PWROK_DLY_SEL")
	)
	(segment
		(start 267.285216 -116.843048)
		(end 268.974316 -115.153948)
		(width 0.127)
		(layer "In15.Cu")
		(net "FM_PS_PWROK_DLY_SEL")
	)
	(segment
		(start 186.63158 -110.569248)
		(end 186.8678 -110.333028)
		(width 0.127)
		(layer "In15.Cu")
		(net "FM_PS_PWROK_DLY_SEL")
	)
	(segment
		(start 192.536826 -106.873548)
		(end 206.920592 -106.873548)
		(width 0.127)
		(layer "In15.Cu")
		(net "FM_PS_PWROK_DLY_SEL")
	)
	(segment
		(start 280.7589 -115.153948)
		(end 283.44368 -112.469168)
		(width 0.127)
		(layer "In15.Cu")
		(net "FM_PS_PWROK_DLY_SEL")
	)
	(segment
		(start 330.04252 -112.469168)
		(end 330.53274 -111.978948)
		(width 0.127)
		(layer "In15.Cu")
		(net "FM_PS_PWROK_DLY_SEL")
	)
	(segment
		(start 216.22766 -104.239568)
		(end 217.09888 -103.368348)
		(width 0.127)
		(layer "In15.Cu")
		(net "FM_PS_PWROK_DLY_SEL")
	)
	(segment
		(start 240.611152 -112.956848)
		(end 246.850408 -112.956848)
		(width 0.127)
		(layer "In15.Cu")
		(net "FM_PS_PWROK_DLY_SEL")
	)
	(segment
		(start 250.736608 -116.843048)
		(end 267.285216 -116.843048)
		(width 0.127)
		(layer "In15.Cu")
		(net "FM_PS_PWROK_DLY_SEL")
	)
	(segment
		(start 232.292652 -104.638348)
		(end 240.611152 -112.956848)
		(width 0.127)
		(layer "In15.Cu")
		(net "FM_PS_PWROK_DLY_SEL")
	)
	(segment
		(start 218.66098 -103.368348)
		(end 219.93098 -104.638348)
		(width 0.127)
		(layer "In15.Cu")
		(net "FM_PS_PWROK_DLY_SEL")
	)
	(segment
		(start 184.155588 -110.975394)
		(end 184.561734 -110.569248)
		(width 0.127)
		(layer "In15.Cu")
		(net "FM_PS_PWROK_DLY_SEL")
	)
	(segment
		(start 246.850408 -112.956848)
		(end 250.736608 -116.843048)
		(width 0.127)
		(layer "In15.Cu")
		(net "FM_PS_PWROK_DLY_SEL")
	)
	(segment
		(start 268.974316 -115.153948)
		(end 280.7589 -115.153948)
		(width 0.127)
		(layer "In15.Cu")
		(net "FM_PS_PWROK_DLY_SEL")
	)
	(segment
		(start 217.09888 -103.368348)
		(end 218.66098 -103.368348)
		(width 0.127)
		(layer "In15.Cu")
		(net "FM_PS_PWROK_DLY_SEL")
	)
	(segment
		(start 189.077346 -110.333028)
		(end 192.536826 -106.873548)
		(width 0.127)
		(layer "In15.Cu")
		(net "FM_PS_PWROK_DLY_SEL")
	)
	(segment
		(start 184.561734 -110.569248)
		(end 186.63158 -110.569248)
		(width 0.127)
		(layer "In15.Cu")
		(net "FM_PS_PWROK_DLY_SEL")
	)
	(segment
		(start 283.44368 -112.469168)
		(end 330.04252 -112.469168)
		(width 0.127)
		(layer "In15.Cu")
		(net "FM_PS_PWROK_DLY_SEL")
	)
	(segment
		(start 335.138268 -40.461946)
		(end 335.67878 -40.461946)
		(width 0.12954)
		(layer "F.Cu")
		(net "FM_PS_PWROK_DLY_R_SEL")
	)
	(via
		(at 340.796372 -33.218374)
		(size 0.6604)
		(drill 0.3302)
		(layers "F.Cu" "B.Cu")
		(net "FM_PS_PWROK_DLY_R_SEL")
	)
	(via
		(at 335.138268 -40.461946)
		(size 0.4572)
		(drill 0.2032)
		(layers "F.Cu" "B.Cu")
		(net "FM_PS_PWROK_DLY_R_SEL")
	)
	(segment
		(start 335.459578 -40.140636)
		(end 335.459578 -39.940992)
		(width 0.0889)
		(layer "B.Cu")
		(net "FM_PS_PWROK_DLY_R_SEL")
	)
	(segment
		(start 340.872064 -30.636972)
		(end 340.872064 -31.678372)
		(width 0.12954)
		(layer "B.Cu")
		(net "FM_PS_PWROK_DLY_R_SEL")
	)
	(segment
		(start 340.796372 -31.754064)
		(end 340.872064 -31.678372)
		(width 0.12954)
		(layer "B.Cu")
		(net "FM_PS_PWROK_DLY_R_SEL")
	)
	(segment
		(start 335.459578 -39.940992)
		(end 335.964022 -39.436548)
		(width 0.0889)
		(layer "B.Cu")
		(net "FM_PS_PWROK_DLY_R_SEL")
	)
	(segment
		(start 338.958174 -36.442396)
		(end 338.958174 -35.222688)
		(width 0.12954)
		(layer "B.Cu")
		(net "FM_PS_PWROK_DLY_R_SEL")
	)
	(segment
		(start 335.138268 -40.461946)
		(end 335.459578 -40.140636)
		(width 0.0889)
		(layer "B.Cu")
		(net "FM_PS_PWROK_DLY_R_SEL")
	)
	(segment
		(start 340.796372 -33.38449)
		(end 340.796372 -33.218374)
		(width 0.12954)
		(layer "B.Cu")
		(net "FM_PS_PWROK_DLY_R_SEL")
	)
	(segment
		(start 340.796372 -33.218374)
		(end 340.796372 -31.754064)
		(width 0.12954)
		(layer "B.Cu")
		(net "FM_PS_PWROK_DLY_R_SEL")
	)
	(segment
		(start 338.958174 -35.222688)
		(end 340.796372 -33.38449)
		(width 0.12954)
		(layer "B.Cu")
		(net "FM_PS_PWROK_DLY_R_SEL")
	)
	(segment
		(start 335.964022 -39.436548)
		(end 338.958174 -36.442396)
		(width 0.12954)
		(layer "B.Cu")
		(net "FM_PS_PWROK_DLY_R_SEL")
	)
	(segment
		(start 139.89304 -80.442308)
		(end 139.89304 -79.150464)
		(width 0.12954)
		(layer "F.Cu")
		(net "FM_PS_EN_PLD_R")
	)
	(segment
		(start 140.081 -80.630268)
		(end 139.89304 -80.442308)
		(width 0.12954)
		(layer "F.Cu")
		(net "FM_PS_EN_PLD_R")
	)
	(segment
		(start 149.91588 -85.613748)
		(end 148.951696 -85.613748)
		(width 0.12954)
		(layer "F.Cu")
		(net "FM_PS_EN_PLD_R")
	)
	(segment
		(start 150.65248 -86.350348)
		(end 149.91588 -85.613748)
		(width 0.12954)
		(layer "F.Cu")
		(net "FM_PS_EN_PLD_R")
	)
	(segment
		(start 183.755538 -121.775474)
		(end 184.183528 -122.203464)
		(width 0.12954)
		(layer "F.Cu")
		(net "FM_PS_EN_PLD_R")
	)
	(segment
		(start 143.968216 -80.630268)
		(end 140.081 -80.630268)
		(width 0.12954)
		(layer "F.Cu")
		(net "FM_PS_EN_PLD_R")
	)
	(segment
		(start 148.951696 -85.613748)
		(end 143.968216 -80.630268)
		(width 0.12954)
		(layer "F.Cu")
		(net "FM_PS_EN_PLD_R")
	)
	(segment
		(start 167.013128 -133.046724)
		(end 166.34333 -132.376926)
		(width 0.12954)
		(layer "F.Cu")
		(net "FM_PS_EN_PLD_R")
	)
	(segment
		(start 150.65248 -87.066628)
		(end 150.65248 -86.350348)
		(width 0.12954)
		(layer "F.Cu")
		(net "FM_PS_EN_PLD_R")
	)
	(segment
		(start 168.58488 -133.046724)
		(end 167.013128 -133.046724)
		(width 0.12954)
		(layer "F.Cu")
		(net "FM_PS_EN_PLD_R")
	)
	(via
		(at 168.58488 -133.046724)
		(size 0.508)
		(drill 0.254)
		(layers "F.Cu" "B.Cu")
		(net "FM_PS_EN_PLD_R")
	)
	(via
		(at 186.79922 -131.282948)
		(size 0.508)
		(drill 0.254)
		(layers "F.Cu" "B.Cu")
		(net "FM_PS_EN_PLD_R")
	)
	(via
		(at 150.65248 -87.066628)
		(size 0.508)
		(drill 0.254)
		(layers "F.Cu" "B.Cu")
		(net "FM_PS_EN_PLD_R")
	)
	(via
		(at 184.183528 -122.203464)
		(size 0.4572)
		(drill 0.254)
		(layers "F.Cu" "B.Cu")
		(net "FM_PS_EN_PLD_R")
	)
	(segment
		(start 184.183528 -122.8471)
		(end 187.34786 -126.011432)
		(width 0.12954)
		(layer "B.Cu")
		(net "FM_PS_EN_PLD_R")
	)
	(segment
		(start 187.21832 -131.282948)
		(end 186.79922 -131.282948)
		(width 0.12954)
		(layer "B.Cu")
		(net "FM_PS_EN_PLD_R")
	)
	(segment
		(start 187.34786 -131.153408)
		(end 187.21832 -131.282948)
		(width 0.12954)
		(layer "B.Cu")
		(net "FM_PS_EN_PLD_R")
	)
	(segment
		(start 187.34786 -126.011432)
		(end 187.34786 -131.153408)
		(width 0.12954)
		(layer "B.Cu")
		(net "FM_PS_EN_PLD_R")
	)
	(segment
		(start 184.183528 -122.203464)
		(end 184.183528 -122.8471)
		(width 0.12954)
		(layer "B.Cu")
		(net "FM_PS_EN_PLD_R")
	)
	(segment
		(start 155.33116 -91.405456)
		(end 155.33116 -104.04348)
		(width 0.127)
		(layer "In2.Cu")
		(net "FM_PS_EN_PLD_R")
	)
	(segment
		(start 161.6456 -110.763812)
		(end 161.6456 -113.396268)
		(width 0.127)
		(layer "In2.Cu")
		(net "FM_PS_EN_PLD_R")
	)
	(segment
		(start 164.67582 -115.235228)
		(end 164.67582 -126.870968)
		(width 0.127)
		(layer "In2.Cu")
		(net "FM_PS_EN_PLD_R")
	)
	(segment
		(start 167.783764 -133.046724)
		(end 168.58488 -133.046724)
		(width 0.127)
		(layer "In2.Cu")
		(net "FM_PS_EN_PLD_R")
	)
	(segment
		(start 150.65756 -87.061548)
		(end 150.987252 -87.061548)
		(width 0.127)
		(layer "In2.Cu")
		(net "FM_PS_EN_PLD_R")
	)
	(segment
		(start 161.6456 -113.396268)
		(end 162.4965 -114.247168)
		(width 0.127)
		(layer "In2.Cu")
		(net "FM_PS_EN_PLD_R")
	)
	(segment
		(start 163.68776 -114.247168)
		(end 164.67582 -115.235228)
		(width 0.127)
		(layer "In2.Cu")
		(net "FM_PS_EN_PLD_R")
	)
	(segment
		(start 155.33116 -104.04348)
		(end 157.831028 -106.543348)
		(width 0.127)
		(layer "In2.Cu")
		(net "FM_PS_EN_PLD_R")
	)
	(segment
		(start 166.15664 -131.4196)
		(end 167.783764 -133.046724)
		(width 0.127)
		(layer "In2.Cu")
		(net "FM_PS_EN_PLD_R")
	)
	(segment
		(start 162.4965 -114.247168)
		(end 163.68776 -114.247168)
		(width 0.127)
		(layer "In2.Cu")
		(net "FM_PS_EN_PLD_R")
	)
	(segment
		(start 160.51403 -109.632242)
		(end 161.6456 -110.763812)
		(width 0.127)
		(layer "In2.Cu")
		(net "FM_PS_EN_PLD_R")
	)
	(segment
		(start 166.15664 -128.351788)
		(end 166.15664 -131.4196)
		(width 0.127)
		(layer "In2.Cu")
		(net "FM_PS_EN_PLD_R")
	)
	(segment
		(start 164.67582 -126.870968)
		(end 166.15664 -128.351788)
		(width 0.127)
		(layer "In2.Cu")
		(net "FM_PS_EN_PLD_R")
	)
	(segment
		(start 157.831028 -106.543348)
		(end 160.2232 -106.543348)
		(width 0.127)
		(layer "In2.Cu")
		(net "FM_PS_EN_PLD_R")
	)
	(segment
		(start 160.51403 -106.834178)
		(end 160.51403 -109.632242)
		(width 0.127)
		(layer "In2.Cu")
		(net "FM_PS_EN_PLD_R")
	)
	(segment
		(start 150.987252 -87.061548)
		(end 155.33116 -91.405456)
		(width 0.127)
		(layer "In2.Cu")
		(net "FM_PS_EN_PLD_R")
	)
	(segment
		(start 150.65248 -87.066628)
		(end 150.65756 -87.061548)
		(width 0.127)
		(layer "In2.Cu")
		(net "FM_PS_EN_PLD_R")
	)
	(segment
		(start 160.2232 -106.543348)
		(end 160.51403 -106.834178)
		(width 0.127)
		(layer "In2.Cu")
		(net "FM_PS_EN_PLD_R")
	)
	(segment
		(start 176.258474 -133.77799)
		(end 169.316146 -133.77799)
		(width 0.127)
		(layer "In15.Cu")
		(net "FM_PS_EN_PLD_R")
	)
	(segment
		(start 176.669192 -134.188708)
		(end 176.258474 -133.77799)
		(width 0.127)
		(layer "In15.Cu")
		(net "FM_PS_EN_PLD_R")
	)
	(segment
		(start 186.79922 -131.514342)
		(end 187.262008 -131.97713)
		(width 0.127)
		(layer "In15.Cu")
		(net "FM_PS_EN_PLD_R")
	)
	(segment
		(start 186.118754 -133.58749)
		(end 185.253122 -134.453122)
		(width 0.127)
		(layer "In15.Cu")
		(net "FM_PS_EN_PLD_R")
	)
	(segment
		(start 186.79922 -131.282948)
		(end 186.79922 -131.514342)
		(width 0.127)
		(layer "In15.Cu")
		(net "FM_PS_EN_PLD_R")
	)
	(segment
		(start 187.262008 -131.97713)
		(end 187.262008 -133.388354)
		(width 0.127)
		(layer "In15.Cu")
		(net "FM_PS_EN_PLD_R")
	)
	(segment
		(start 187.062872 -133.58749)
		(end 186.118754 -133.58749)
		(width 0.127)
		(layer "In15.Cu")
		(net "FM_PS_EN_PLD_R")
	)
	(segment
		(start 180.050186 -134.453122)
		(end 179.785772 -134.188708)
		(width 0.127)
		(layer "In15.Cu")
		(net "FM_PS_EN_PLD_R")
	)
	(segment
		(start 185.253122 -134.453122)
		(end 180.050186 -134.453122)
		(width 0.127)
		(layer "In15.Cu")
		(net "FM_PS_EN_PLD_R")
	)
	(segment
		(start 179.785772 -134.188708)
		(end 176.669192 -134.188708)
		(width 0.127)
		(layer "In15.Cu")
		(net "FM_PS_EN_PLD_R")
	)
	(segment
		(start 187.262008 -133.388354)
		(end 187.062872 -133.58749)
		(width 0.127)
		(layer "In15.Cu")
		(net "FM_PS_EN_PLD_R")
	)
	(segment
		(start 169.316146 -133.77799)
		(end 168.58488 -133.046724)
		(width 0.127)
		(layer "In15.Cu")
		(net "FM_PS_EN_PLD_R")
	)
	(segment
		(start 323.365622 -40.422322)
		(end 324.799452 -41.856152)
		(width 0.12954)
		(layer "F.Cu")
		(net "FM_PMBUS_ALERT_B_EN")
	)
	(segment
		(start 324.799452 -41.856152)
		(end 325.136002 -42.192702)
		(width 0.0889)
		(layer "F.Cu")
		(net "FM_PMBUS_ALERT_B_EN")
	)
	(segment
		(start 323.076316 -40.422322)
		(end 323.365622 -40.422322)
		(width 0.12954)
		(layer "F.Cu")
		(net "FM_PMBUS_ALERT_B_EN")
	)
	(segment
		(start 327.132696 -41.947084)
		(end 327.41489 -41.947084)
		(width 0.0889)
		(layer "F.Cu")
		(net "FM_PMBUS_ALERT_B_EN")
	)
	(segment
		(start 325.136002 -42.192702)
		(end 326.3392 -42.192702)
		(width 0.0889)
		(layer "F.Cu")
		(net "FM_PMBUS_ALERT_B_EN")
	)
	(segment
		(start 326.3392 -42.192702)
		(end 326.444356 -42.22369)
		(width 0.0889)
		(layer "F.Cu")
		(net "FM_PMBUS_ALERT_B_EN")
	)
	(segment
		(start 326.718422 -42.22369)
		(end 327.132696 -41.947084)
		(width 0.0889)
		(layer "F.Cu")
		(net "FM_PMBUS_ALERT_B_EN")
	)
	(segment
		(start 326.444356 -42.22369)
		(end 326.718422 -42.22369)
		(width 0.0889)
		(layer "F.Cu")
		(net "FM_PMBUS_ALERT_B_EN")
	)
	(via
		(at 323.076316 -40.422322)
		(size 0.508)
		(drill 0.254)
		(layers "F.Cu" "B.Cu")
		(net "FM_PMBUS_ALERT_B_EN")
	)
	(segment
		(start 322.21678 -40.422322)
		(end 321.652138 -39.85768)
		(width 0.12954)
		(layer "B.Cu")
		(net "FM_PMBUS_ALERT_B_EN")
	)
	(segment
		(start 323.076316 -40.422322)
		(end 322.21678 -40.422322)
		(width 0.12954)
		(layer "B.Cu")
		(net "FM_PMBUS_ALERT_B_EN")
	)
	(segment
		(start 320.295524 -52.137564)
		(end 320.556382 -51.876706)
		(width 0.12954)
		(layer "F.Cu")
		(net "FM_PLT_BMC_THERMTRIP_R_N")
	)
	(segment
		(start 325.613522 -50.451258)
		(end 326.999854 -50.451258)
		(width 0.0889)
		(layer "F.Cu")
		(net "FM_PLT_BMC_THERMTRIP_R_N")
	)
	(segment
		(start 324.221348 -50.688748)
		(end 325.376032 -50.688748)
		(width 0.0889)
		(layer "F.Cu")
		(net "FM_PLT_BMC_THERMTRIP_R_N")
	)
	(segment
		(start 317.330582 -52.628038)
		(end 316.270386 -52.628038)
		(width 0.12954)
		(layer "F.Cu")
		(net "FM_PLT_BMC_THERMTRIP_R_N")
	)
	(segment
		(start 322.167504 -51.876706)
		(end 322.654422 -51.389788)
		(width 0.12954)
		(layer "F.Cu")
		(net "FM_PLT_BMC_THERMTRIP_R_N")
	)
	(segment
		(start 320.556382 -51.876706)
		(end 322.167504 -51.876706)
		(width 0.12954)
		(layer "F.Cu")
		(net "FM_PLT_BMC_THERMTRIP_R_N")
	)
	(segment
		(start 317.821056 -52.137564)
		(end 319.18021 -52.137564)
		(width 0.12954)
		(layer "F.Cu")
		(net "FM_PLT_BMC_THERMTRIP_R_N")
	)
	(segment
		(start 323.662548 -51.247548)
		(end 324.221348 -50.688748)
		(width 0.0889)
		(layer "F.Cu")
		(net "FM_PLT_BMC_THERMTRIP_R_N")
	)
	(segment
		(start 325.376032 -50.688748)
		(end 325.613522 -50.451258)
		(width 0.0889)
		(layer "F.Cu")
		(net "FM_PLT_BMC_THERMTRIP_R_N")
	)
	(segment
		(start 319.18021 -52.137564)
		(end 320.295524 -52.137564)
		(width 0.12954)
		(layer "F.Cu")
		(net "FM_PLT_BMC_THERMTRIP_R_N")
	)
	(segment
		(start 316.270386 -52.628038)
		(end 315.931296 -52.288948)
		(width 0.12954)
		(layer "F.Cu")
		(net "FM_PLT_BMC_THERMTRIP_R_N")
	)
	(segment
		(start 322.796662 -51.247548)
		(end 323.662548 -51.247548)
		(width 0.0889)
		(layer "F.Cu")
		(net "FM_PLT_BMC_THERMTRIP_R_N")
	)
	(segment
		(start 317.796672 -52.161948)
		(end 317.821056 -52.137564)
		(width 0.12954)
		(layer "F.Cu")
		(net "FM_PLT_BMC_THERMTRIP_R_N")
	)
	(segment
		(start 317.796672 -52.161948)
		(end 317.330582 -52.628038)
		(width 0.12954)
		(layer "F.Cu")
		(net "FM_PLT_BMC_THERMTRIP_R_N")
	)
	(segment
		(start 315.931296 -52.288948)
		(end 315.510672 -52.288948)
		(width 0.12954)
		(layer "F.Cu")
		(net "FM_PLT_BMC_THERMTRIP_R_N")
	)
	(segment
		(start 322.654422 -51.389788)
		(end 322.796662 -51.247548)
		(width 0.0889)
		(layer "F.Cu")
		(net "FM_PLT_BMC_THERMTRIP_R_N")
	)
	(via
		(at 319.18021 -52.137564)
		(size 0.762)
		(drill 0.381)
		(layers "F.Cu" "B.Cu")
		(net "FM_PLT_BMC_THERMTRIP_R_N")
	)
	(segment
		(start 197.59041 -124.170948)
		(end 198.80326 -124.170948)
		(width 0.12954)
		(layer "F.Cu")
		(net "FM_PLD_REV_R_N")
	)
	(via
		(at 198.80326 -124.170948)
		(size 0.508)
		(drill 0.254)
		(layers "F.Cu" "B.Cu")
		(net "FM_PLD_REV_R_N")
	)
	(segment
		(start 197.59041 -124.170948)
		(end 198.80326 -124.170948)
		(width 0.12954)
		(layer "B.Cu")
		(net "FM_PLD_REV_R_N")
	)
	(segment
		(start 190.55588 -121.199148)
		(end 191.16548 -121.808748)
		(width 0.12954)
		(layer "F.Cu")
		(net "FM_PLD_REV_N")
	)
	(segment
		(start 190.55588 -121.199148)
		(end 188.310012 -121.199148)
		(width 0.12954)
		(layer "F.Cu")
		(net "FM_PLD_REV_N")
	)
	(segment
		(start 188.310012 -121.199148)
		(end 187.69203 -120.581166)
		(width 0.12954)
		(layer "F.Cu")
		(net "FM_PLD_REV_N")
	)
	(segment
		(start 196.517514 -124.818648)
		(end 193.26606 -124.818648)
		(width 0.12954)
		(layer "F.Cu")
		(net "FM_PLD_REV_N")
	)
	(segment
		(start 192.33896 -124.170948)
		(end 192.98031 -124.170948)
		(width 0.12954)
		(layer "F.Cu")
		(net "FM_PLD_REV_N")
	)
	(segment
		(start 186.568842 -120.473216)
		(end 186.568842 -119.801132)
		(width 0.12954)
		(layer "F.Cu")
		(net "FM_PLD_REV_N")
	)
	(segment
		(start 186.155584 -119.387874)
		(end 186.155584 -119.375428)
		(width 0.12954)
		(layer "F.Cu")
		(net "FM_PLD_REV_N")
	)
	(segment
		(start 186.568842 -119.801132)
		(end 186.155584 -119.387874)
		(width 0.12954)
		(layer "F.Cu")
		(net "FM_PLD_REV_N")
	)
	(segment
		(start 196.79031 -124.545852)
		(end 196.517514 -124.818648)
		(width 0.12954)
		(layer "F.Cu")
		(net "FM_PLD_REV_N")
	)
	(segment
		(start 192.98031 -124.532898)
		(end 192.98031 -124.170948)
		(width 0.12954)
		(layer "F.Cu")
		(net "FM_PLD_REV_N")
	)
	(segment
		(start 196.79031 -124.170948)
		(end 196.79031 -124.545852)
		(width 0.12954)
		(layer "F.Cu")
		(net "FM_PLD_REV_N")
	)
	(segment
		(start 193.26606 -124.818648)
		(end 192.98031 -124.532898)
		(width 0.12954)
		(layer "F.Cu")
		(net "FM_PLD_REV_N")
	)
	(segment
		(start 186.676792 -120.581166)
		(end 186.568842 -120.473216)
		(width 0.12954)
		(layer "F.Cu")
		(net "FM_PLD_REV_N")
	)
	(segment
		(start 191.16548 -122.997468)
		(end 192.33896 -124.170948)
		(width 0.12954)
		(layer "F.Cu")
		(net "FM_PLD_REV_N")
	)
	(segment
		(start 187.69203 -120.581166)
		(end 186.676792 -120.581166)
		(width 0.12954)
		(layer "F.Cu")
		(net "FM_PLD_REV_N")
	)
	(segment
		(start 191.16548 -121.808748)
		(end 191.16548 -122.997468)
		(width 0.12954)
		(layer "F.Cu")
		(net "FM_PLD_REV_N")
	)
	(via
		(at 190.55588 -121.199148)
		(size 0.762)
		(drill 0.381)
		(layers "F.Cu" "B.Cu")
		(net "FM_PLD_REV_N")
	)
	(segment
		(start 217.12428 -111.105188)
		(end 218.178634 -111.105188)
		(width 0.12954)
		(layer "F.Cu")
		(net "FM_PLD_HEARTBEAT_LVC3_D")
	)
	(segment
		(start 217.12428 -109.421422)
		(end 217.12428 -111.105188)
		(width 0.12954)
		(layer "F.Cu")
		(net "FM_PLD_HEARTBEAT_LVC3_D")
	)
	(segment
		(start 218.188794 -111.115348)
		(end 219.3163 -111.115348)
		(width 0.12954)
		(layer "F.Cu")
		(net "FM_PLD_HEARTBEAT_LVC3_D")
	)
	(segment
		(start 218.178634 -111.105188)
		(end 218.188794 -111.115348)
		(width 0.12954)
		(layer "F.Cu")
		(net "FM_PLD_HEARTBEAT_LVC3_D")
	)
	(via
		(at 217.12428 -111.105188)
		(size 0.762)
		(drill 0.381)
		(layers "F.Cu" "B.Cu")
		(net "FM_PLD_HEARTBEAT_LVC3_D")
	)
	(segment
		(start 216.17432 -107.221274)
		(end 215.00846 -107.221274)
		(width 0.12954)
		(layer "F.Cu")
		(net "FM_PLD_HEARTBEAT_LVC3")
	)
	(segment
		(start 182.155592 -112.175544)
		(end 182.555642 -111.775494)
		(width 0.12954)
		(layer "F.Cu")
		(net "FM_PLD_HEARTBEAT_LVC3")
	)
	(via
		(at 215.00846 -107.221274)
		(size 0.508)
		(drill 0.254)
		(layers "F.Cu" "B.Cu")
		(net "FM_PLD_HEARTBEAT_LVC3")
	)
	(via
		(at 182.555642 -111.775494)
		(size 0.4572)
		(drill 0.254)
		(layers "F.Cu" "B.Cu")
		(net "FM_PLD_HEARTBEAT_LVC3")
	)
	(segment
		(start 182.555642 -111.775494)
		(end 182.954168 -111.376968)
		(width 0.12954)
		(layer "B.Cu")
		(net "FM_PLD_HEARTBEAT_LVC3")
	)
	(segment
		(start 182.954168 -111.376968)
		(end 187.10656 -111.376968)
		(width 0.12954)
		(layer "B.Cu")
		(net "FM_PLD_HEARTBEAT_LVC3")
	)
	(segment
		(start 188.16066 -110.322868)
		(end 190.37681 -110.322868)
		(width 0.12954)
		(layer "B.Cu")
		(net "FM_PLD_HEARTBEAT_LVC3")
	)
	(segment
		(start 187.10656 -111.376968)
		(end 188.16066 -110.322868)
		(width 0.12954)
		(layer "B.Cu")
		(net "FM_PLD_HEARTBEAT_LVC3")
	)
	(segment
		(start 190.37681 -110.322868)
		(end 193.20383 -107.495848)
		(width 0.12954)
		(layer "B.Cu")
		(net "FM_PLD_HEARTBEAT_LVC3")
	)
	(segment
		(start 197.83298 -114.595148)
		(end 197.99808 -114.430048)
		(width 0.127)
		(layer "In15.Cu")
		(net "FM_PLD_HEARTBEAT_LVC3")
	)
	(segment
		(start 186.367928 -113.55324)
		(end 186.520836 -113.706148)
		(width 0.127)
		(layer "In15.Cu")
		(net "FM_PLD_HEARTBEAT_LVC3")
	)
	(segment
		(start 182.555642 -111.775494)
		(end 182.555642 -111.98733)
		(width 0.127)
		(layer "In15.Cu")
		(net "FM_PLD_HEARTBEAT_LVC3")
	)
	(segment
		(start 182.555642 -111.98733)
		(end 182.95366 -112.385348)
		(width 0.127)
		(layer "In15.Cu")
		(net "FM_PLD_HEARTBEAT_LVC3")
	)
	(segment
		(start 192.57518 -114.595148)
		(end 197.83298 -114.595148)
		(width 0.127)
		(layer "In15.Cu")
		(net "FM_PLD_HEARTBEAT_LVC3")
	)
	(segment
		(start 210.240626 -110.968028)
		(end 213.1187 -108.089954)
		(width 0.127)
		(layer "In15.Cu")
		(net "FM_PLD_HEARTBEAT_LVC3")
	)
	(segment
		(start 198.72452 -113.284508)
		(end 198.91248 -113.096548)
		(width 0.127)
		(layer "In15.Cu")
		(net "FM_PLD_HEARTBEAT_LVC3")
	)
	(segment
		(start 191.68618 -113.706148)
		(end 192.57518 -114.595148)
		(width 0.127)
		(layer "In15.Cu")
		(net "FM_PLD_HEARTBEAT_LVC3")
	)
	(segment
		(start 198.91248 -113.096548)
		(end 198.91248 -112.687608)
		(width 0.127)
		(layer "In15.Cu")
		(net "FM_PLD_HEARTBEAT_LVC3")
	)
	(segment
		(start 198.5772 -114.430048)
		(end 198.72452 -114.282728)
		(width 0.127)
		(layer "In15.Cu")
		(net "FM_PLD_HEARTBEAT_LVC3")
	)
	(segment
		(start 198.91248 -112.687608)
		(end 199.2757 -112.324388)
		(width 0.127)
		(layer "In15.Cu")
		(net "FM_PLD_HEARTBEAT_LVC3")
	)
	(segment
		(start 182.95366 -112.385348)
		(end 182.95366 -112.852708)
		(width 0.127)
		(layer "In15.Cu")
		(net "FM_PLD_HEARTBEAT_LVC3")
	)
	(segment
		(start 214.13978 -108.089954)
		(end 215.00846 -107.221274)
		(width 0.127)
		(layer "In15.Cu")
		(net "FM_PLD_HEARTBEAT_LVC3")
	)
	(segment
		(start 205.58252 -112.324388)
		(end 206.93888 -110.968028)
		(width 0.127)
		(layer "In15.Cu")
		(net "FM_PLD_HEARTBEAT_LVC3")
	)
	(segment
		(start 186.520836 -113.706148)
		(end 191.68618 -113.706148)
		(width 0.127)
		(layer "In15.Cu")
		(net "FM_PLD_HEARTBEAT_LVC3")
	)
	(segment
		(start 213.1187 -108.089954)
		(end 214.13978 -108.089954)
		(width 0.127)
		(layer "In15.Cu")
		(net "FM_PLD_HEARTBEAT_LVC3")
	)
	(segment
		(start 198.72452 -114.282728)
		(end 198.72452 -113.284508)
		(width 0.127)
		(layer "In15.Cu")
		(net "FM_PLD_HEARTBEAT_LVC3")
	)
	(segment
		(start 182.95366 -112.852708)
		(end 183.654192 -113.55324)
		(width 0.127)
		(layer "In15.Cu")
		(net "FM_PLD_HEARTBEAT_LVC3")
	)
	(segment
		(start 199.2757 -112.324388)
		(end 205.58252 -112.324388)
		(width 0.127)
		(layer "In15.Cu")
		(net "FM_PLD_HEARTBEAT_LVC3")
	)
	(segment
		(start 206.93888 -110.968028)
		(end 210.240626 -110.968028)
		(width 0.127)
		(layer "In15.Cu")
		(net "FM_PLD_HEARTBEAT_LVC3")
	)
	(segment
		(start 183.654192 -113.55324)
		(end 186.367928 -113.55324)
		(width 0.127)
		(layer "In15.Cu")
		(net "FM_PLD_HEARTBEAT_LVC3")
	)
	(segment
		(start 197.99808 -114.430048)
		(end 198.5772 -114.430048)
		(width 0.127)
		(layer "In15.Cu")
		(net "FM_PLD_HEARTBEAT_LVC3")
	)
	(segment
		(start 197.01383 -106.225848)
		(end 197.01383 -107.495848)
		(width 0.12954)
		(layer "F.Cu")
		(net "FM_PLD_CLK_25M_R_EN")
	)
	(segment
		(start 196.690742 -105.90276)
		(end 197.01383 -106.225848)
		(width 0.12954)
		(layer "F.Cu")
		(net "FM_PLD_CLK_25M_R_EN")
	)
	(segment
		(start 195.8467 -105.90276)
		(end 196.690742 -105.90276)
		(width 0.12954)
		(layer "F.Cu")
		(net "FM_PLD_CLK_25M_R_EN")
	)
	(segment
		(start 182.155592 -110.575344)
		(end 182.555642 -110.175294)
		(width 0.12954)
		(layer "F.Cu")
		(net "FM_PLD_CLK_25M_R_EN")
	)
	(via
		(at 195.8467 -105.90276)
		(size 0.508)
		(drill 0.254)
		(layers "F.Cu" "B.Cu")
		(net "FM_PLD_CLK_25M_R_EN")
	)
	(via
		(at 182.555642 -110.175294)
		(size 0.4572)
		(drill 0.254)
		(layers "F.Cu" "B.Cu")
		(net "FM_PLD_CLK_25M_R_EN")
	)
	(segment
		(start 194.16522 -107.025948)
		(end 190.985648 -110.20552)
		(width 0.127)
		(layer "In6.Cu")
		(net "FM_PLD_CLK_25M_R_EN")
	)
	(segment
		(start 190.985648 -110.20552)
		(end 186.79414 -110.20552)
		(width 0.127)
		(layer "In6.Cu")
		(net "FM_PLD_CLK_25M_R_EN")
	)
	(segment
		(start 195.8467 -106.534966)
		(end 195.355718 -107.025948)
		(width 0.127)
		(layer "In6.Cu")
		(net "FM_PLD_CLK_25M_R_EN")
	)
	(segment
		(start 195.355718 -107.025948)
		(end 194.16522 -107.025948)
		(width 0.127)
		(layer "In6.Cu")
		(net "FM_PLD_CLK_25M_R_EN")
	)
	(segment
		(start 186.427872 -110.571788)
		(end 182.952136 -110.571788)
		(width 0.127)
		(layer "In6.Cu")
		(net "FM_PLD_CLK_25M_R_EN")
	)
	(segment
		(start 186.79414 -110.20552)
		(end 186.427872 -110.571788)
		(width 0.127)
		(layer "In6.Cu")
		(net "FM_PLD_CLK_25M_R_EN")
	)
	(segment
		(start 182.952136 -110.571788)
		(end 182.555642 -110.175294)
		(width 0.127)
		(layer "In6.Cu")
		(net "FM_PLD_CLK_25M_R_EN")
	)
	(segment
		(start 195.8467 -105.90276)
		(end 195.8467 -106.534966)
		(width 0.127)
		(layer "In6.Cu")
		(net "FM_PLD_CLK_25M_R_EN")
	)
	(segment
		(start 197.81393 -107.495848)
		(end 198.42353 -107.495848)
		(width 0.12954)
		(layer "F.Cu")
		(net "FM_PLD_CLK_25M_EN")
	)
	(via
		(at 248.72696 -108.003848)
		(size 0.508)
		(drill 0.254)
		(layers "F.Cu" "B.Cu")
		(net "FM_PLD_CLK_25M_EN")
	)
	(via
		(at 198.42353 -107.495848)
		(size 0.508)
		(drill 0.254)
		(layers "F.Cu" "B.Cu")
		(net "FM_PLD_CLK_25M_EN")
	)
	(segment
		(start 251.007626 -106.149648)
		(end 251.007626 -105.656634)
		(width 0.12954)
		(layer "B.Cu")
		(net "FM_PLD_CLK_25M_EN")
	)
	(segment
		(start 249.7836 -106.947208)
		(end 250.210066 -106.947208)
		(width 0.12954)
		(layer "B.Cu")
		(net "FM_PLD_CLK_25M_EN")
	)
	(segment
		(start 250.210066 -106.947208)
		(end 251.007626 -106.149648)
		(width 0.12954)
		(layer "B.Cu")
		(net "FM_PLD_CLK_25M_EN")
	)
	(segment
		(start 248.72696 -108.003848)
		(end 249.7836 -106.947208)
		(width 0.12954)
		(layer "B.Cu")
		(net "FM_PLD_CLK_25M_EN")
	)
	(segment
		(start 245.493286 -104.770174)
		(end 248.72696 -108.003848)
		(width 0.127)
		(layer "In13.Cu")
		(net "FM_PLD_CLK_25M_EN")
	)
	(segment
		(start 229.710488 -109.121448)
		(end 234.061762 -104.770174)
		(width 0.127)
		(layer "In13.Cu")
		(net "FM_PLD_CLK_25M_EN")
	)
	(segment
		(start 199.02297 -108.095288)
		(end 204.56144 -108.095288)
		(width 0.127)
		(layer "In13.Cu")
		(net "FM_PLD_CLK_25M_EN")
	)
	(segment
		(start 216.408254 -109.5502)
		(end 216.837006 -109.121448)
		(width 0.127)
		(layer "In13.Cu")
		(net "FM_PLD_CLK_25M_EN")
	)
	(segment
		(start 198.42353 -107.495848)
		(end 199.02297 -108.095288)
		(width 0.127)
		(layer "In13.Cu")
		(net "FM_PLD_CLK_25M_EN")
	)
	(segment
		(start 234.061762 -104.770174)
		(end 245.493286 -104.770174)
		(width 0.127)
		(layer "In13.Cu")
		(net "FM_PLD_CLK_25M_EN")
	)
	(segment
		(start 204.56144 -108.095288)
		(end 206.016352 -109.5502)
		(width 0.127)
		(layer "In13.Cu")
		(net "FM_PLD_CLK_25M_EN")
	)
	(segment
		(start 216.837006 -109.121448)
		(end 229.710488 -109.121448)
		(width 0.127)
		(layer "In13.Cu")
		(net "FM_PLD_CLK_25M_EN")
	)
	(segment
		(start 206.016352 -109.5502)
		(end 216.408254 -109.5502)
		(width 0.127)
		(layer "In13.Cu")
		(net "FM_PLD_CLK_25M_EN")
	)
	(segment
		(start 271.67332 -97.076514)
		(end 271.68602 -97.063814)
		(width 0.12954)
		(layer "F.Cu")
		(net "FM_PLD_CLKS_OE_R_N")
	)
	(segment
		(start 270.08582 -97.043748)
		(end 271.665954 -97.043748)
		(width 0.12954)
		(layer "F.Cu")
		(net "FM_PLD_CLKS_OE_R_N")
	)
	(segment
		(start 271.665954 -97.043748)
		(end 271.68602 -97.063814)
		(width 0.12954)
		(layer "F.Cu")
		(net "FM_PLD_CLKS_OE_R_N")
	)
	(segment
		(start 270.08582 -95.070422)
		(end 270.08582 -97.043748)
		(width 0.12954)
		(layer "F.Cu")
		(net "FM_PLD_CLKS_OE_R_N")
	)
	(segment
		(start 271.67332 -98.227642)
		(end 271.67332 -97.076514)
		(width 0.12954)
		(layer "F.Cu")
		(net "FM_PLD_CLKS_OE_R_N")
	)
	(via
		(at 270.08582 -97.043748)
		(size 0.762)
		(drill 0.381)
		(layers "F.Cu" "B.Cu")
		(net "FM_PLD_CLKS_OE_R_N")
	)
	(segment
		(start 182.955692 -109.775498)
		(end 183.355742 -109.375448)
		(width 0.12954)
		(layer "F.Cu")
		(net "FM_PLD_CLKS_DEV_R_EN")
	)
	(via
		(at 234.669838 -113.16843)
		(size 0.762)
		(drill 0.254)
		(layers "F.Cu" "B.Cu")
		(net "FM_PLD_CLKS_DEV_R_EN")
	)
	(via
		(at 183.355742 -109.375448)
		(size 0.4572)
		(drill 0.254)
		(layers "F.Cu" "B.Cu")
		(net "FM_PLD_CLKS_DEV_R_EN")
	)
	(via
		(at 231.0384 -132.375148)
		(size 0.508)
		(drill 0.254)
		(layers "F.Cu" "B.Cu")
		(net "FM_PLD_CLKS_DEV_R_EN")
	)
	(segment
		(start 233.966766 -132.080254)
		(end 233.971846 -132.075174)
		(width 0.12954)
		(layer "B.Cu")
		(net "FM_PLD_CLKS_DEV_R_EN")
	)
	(segment
		(start 233.34218 -131.516628)
		(end 233.905806 -132.080254)
		(width 0.12954)
		(layer "B.Cu")
		(net "FM_PLD_CLKS_DEV_R_EN")
	)
	(segment
		(start 231.89692 -131.516628)
		(end 233.34218 -131.516628)
		(width 0.12954)
		(layer "B.Cu")
		(net "FM_PLD_CLKS_DEV_R_EN")
	)
	(segment
		(start 231.0384 -132.375148)
		(end 231.89692 -131.516628)
		(width 0.12954)
		(layer "B.Cu")
		(net "FM_PLD_CLKS_DEV_R_EN")
	)
	(segment
		(start 233.905806 -132.080254)
		(end 233.966766 -132.080254)
		(width 0.12954)
		(layer "B.Cu")
		(net "FM_PLD_CLKS_DEV_R_EN")
	)
	(segment
		(start 231.16286 -113.985548)
		(end 233.85272 -113.985548)
		(width 0.127)
		(layer "In2.Cu")
		(net "FM_PLD_CLKS_DEV_R_EN")
	)
	(segment
		(start 230.71836 -129.230628)
		(end 229.6795 -128.191768)
		(width 0.127)
		(layer "In2.Cu")
		(net "FM_PLD_CLKS_DEV_R_EN")
	)
	(segment
		(start 231.0384 -132.375148)
		(end 230.71836 -132.055108)
		(width 0.127)
		(layer "In2.Cu")
		(net "FM_PLD_CLKS_DEV_R_EN")
	)
	(segment
		(start 230.066596 -115.081812)
		(end 231.16286 -113.985548)
		(width 0.127)
		(layer "In2.Cu")
		(net "FM_PLD_CLKS_DEV_R_EN")
	)
	(segment
		(start 229.6795 -120.101868)
		(end 230.066596 -119.714772)
		(width 0.127)
		(layer "In2.Cu")
		(net "FM_PLD_CLKS_DEV_R_EN")
	)
	(segment
		(start 230.71836 -132.055108)
		(end 230.71836 -129.230628)
		(width 0.127)
		(layer "In2.Cu")
		(net "FM_PLD_CLKS_DEV_R_EN")
	)
	(segment
		(start 230.066596 -119.714772)
		(end 230.066596 -115.081812)
		(width 0.127)
		(layer "In2.Cu")
		(net "FM_PLD_CLKS_DEV_R_EN")
	)
	(segment
		(start 229.6795 -128.191768)
		(end 229.6795 -120.101868)
		(width 0.127)
		(layer "In2.Cu")
		(net "FM_PLD_CLKS_DEV_R_EN")
	)
	(segment
		(start 233.85272 -113.985548)
		(end 234.669838 -113.16843)
		(width 0.127)
		(layer "In2.Cu")
		(net "FM_PLD_CLKS_DEV_R_EN")
	)
	(segment
		(start 182.960772 -113.78184)
		(end 182.15356 -112.974628)
		(width 0.127)
		(layer "In15.Cu")
		(net "FM_PLD_CLKS_DEV_R_EN")
	)
	(segment
		(start 234.669838 -113.16843)
		(end 233.719116 -112.217708)
		(width 0.127)
		(layer "In15.Cu")
		(net "FM_PLD_CLKS_DEV_R_EN")
	)
	(segment
		(start 209.71764 -112.217708)
		(end 208.5975 -113.337848)
		(width 0.127)
		(layer "In15.Cu")
		(net "FM_PLD_CLKS_DEV_R_EN")
	)
	(segment
		(start 233.719116 -112.217708)
		(end 209.71764 -112.217708)
		(width 0.127)
		(layer "In15.Cu")
		(net "FM_PLD_CLKS_DEV_R_EN")
	)
	(segment
		(start 183.355742 -109.582966)
		(end 183.355742 -109.375448)
		(width 0.127)
		(layer "In15.Cu")
		(net "FM_PLD_CLKS_DEV_R_EN")
	)
	(segment
		(start 182.15356 -110.769908)
		(end 182.35422 -110.569248)
		(width 0.127)
		(layer "In15.Cu")
		(net "FM_PLD_CLKS_DEV_R_EN")
	)
	(segment
		(start 182.95366 -110.442248)
		(end 182.95366 -109.985048)
		(width 0.127)
		(layer "In15.Cu")
		(net "FM_PLD_CLKS_DEV_R_EN")
	)
	(segment
		(start 208.5975 -113.337848)
		(end 203.26604 -113.337848)
		(width 0.127)
		(layer "In15.Cu")
		(net "FM_PLD_CLKS_DEV_R_EN")
	)
	(segment
		(start 191.470534 -114.137948)
		(end 186.58332 -114.137948)
		(width 0.127)
		(layer "In15.Cu")
		(net "FM_PLD_CLKS_DEV_R_EN")
	)
	(segment
		(start 199.20458 -114.325908)
		(end 199.20458 -114.645948)
		(width 0.127)
		(layer "In15.Cu")
		(net "FM_PLD_CLKS_DEV_R_EN")
	)
	(segment
		(start 203.03998 -113.563908)
		(end 199.96658 -113.563908)
		(width 0.127)
		(layer "In15.Cu")
		(net "FM_PLD_CLKS_DEV_R_EN")
	)
	(segment
		(start 182.15356 -112.974628)
		(end 182.15356 -110.769908)
		(width 0.127)
		(layer "In15.Cu")
		(net "FM_PLD_CLKS_DEV_R_EN")
	)
	(segment
		(start 199.96658 -113.563908)
		(end 199.20458 -114.325908)
		(width 0.127)
		(layer "In15.Cu")
		(net "FM_PLD_CLKS_DEV_R_EN")
	)
	(segment
		(start 198.0819 -115.052348)
		(end 192.384934 -115.052348)
		(width 0.127)
		(layer "In15.Cu")
		(net "FM_PLD_CLKS_DEV_R_EN")
	)
	(segment
		(start 199.20458 -114.645948)
		(end 198.96836 -114.882168)
		(width 0.127)
		(layer "In15.Cu")
		(net "FM_PLD_CLKS_DEV_R_EN")
	)
	(segment
		(start 182.82666 -110.569248)
		(end 182.95366 -110.442248)
		(width 0.127)
		(layer "In15.Cu")
		(net "FM_PLD_CLKS_DEV_R_EN")
	)
	(segment
		(start 198.96836 -114.882168)
		(end 198.25208 -114.882168)
		(width 0.127)
		(layer "In15.Cu")
		(net "FM_PLD_CLKS_DEV_R_EN")
	)
	(segment
		(start 186.58332 -114.137948)
		(end 186.227212 -113.78184)
		(width 0.127)
		(layer "In15.Cu")
		(net "FM_PLD_CLKS_DEV_R_EN")
	)
	(segment
		(start 192.384934 -115.052348)
		(end 191.470534 -114.137948)
		(width 0.127)
		(layer "In15.Cu")
		(net "FM_PLD_CLKS_DEV_R_EN")
	)
	(segment
		(start 198.25208 -114.882168)
		(end 198.0819 -115.052348)
		(width 0.127)
		(layer "In15.Cu")
		(net "FM_PLD_CLKS_DEV_R_EN")
	)
	(segment
		(start 186.227212 -113.78184)
		(end 182.960772 -113.78184)
		(width 0.127)
		(layer "In15.Cu")
		(net "FM_PLD_CLKS_DEV_R_EN")
	)
	(segment
		(start 203.26604 -113.337848)
		(end 203.03998 -113.563908)
		(width 0.127)
		(layer "In15.Cu")
		(net "FM_PLD_CLKS_DEV_R_EN")
	)
	(segment
		(start 182.95366 -109.985048)
		(end 183.355742 -109.582966)
		(width 0.127)
		(layer "In15.Cu")
		(net "FM_PLD_CLKS_DEV_R_EN")
	)
	(segment
		(start 182.35422 -110.569248)
		(end 182.82666 -110.569248)
		(width 0.127)
		(layer "In15.Cu")
		(net "FM_PLD_CLKS_DEV_R_EN")
	)
	(segment
		(start 263.320784 -88.166194)
		(end 255.191514 -88.166194)
		(width 0.12954)
		(layer "F.Cu")
		(net "FM_PLD_CLKS_DEV_EN")
	)
	(segment
		(start 251.290328 -92.36964)
		(end 251.290328 -92.396056)
		(width 0.12954)
		(layer "F.Cu")
		(net "FM_PLD_CLKS_DEV_EN")
	)
	(segment
		(start 251.951236 -93.056964)
		(end 251.951236 -93.584522)
		(width 0.12954)
		(layer "F.Cu")
		(net "FM_PLD_CLKS_DEV_EN")
	)
	(segment
		(start 252.207522 -92.36964)
		(end 251.290328 -92.36964)
		(width 0.12954)
		(layer "F.Cu")
		(net "FM_PLD_CLKS_DEV_EN")
	)
	(segment
		(start 119.26189 -413.189928)
		(end 119.94388 -413.189928)
		(width 0.12954)
		(layer "F.Cu")
		(net "FM_PLD_CLKS_DEV_EN")
	)
	(segment
		(start 255.191514 -88.166194)
		(end 252.335792 -91.021916)
		(width 0.12954)
		(layer "F.Cu")
		(net "FM_PLD_CLKS_DEV_EN")
	)
	(segment
		(start 251.290328 -92.396056)
		(end 251.951236 -93.056964)
		(width 0.12954)
		(layer "F.Cu")
		(net "FM_PLD_CLKS_DEV_EN")
	)
	(segment
		(start 253.432818 -95.368872)
		(end 251.951236 -93.88729)
		(width 0.12954)
		(layer "F.Cu")
		(net "FM_PLD_CLKS_DEV_EN")
	)
	(segment
		(start 252.335792 -92.24137)
		(end 252.207522 -92.36964)
		(width 0.12954)
		(layer "F.Cu")
		(net "FM_PLD_CLKS_DEV_EN")
	)
	(segment
		(start 268.024864 -92.870274)
		(end 267.38707 -92.23248)
		(width 0.12954)
		(layer "F.Cu")
		(net "FM_PLD_CLKS_DEV_EN")
	)
	(segment
		(start 253.432818 -95.68815)
		(end 253.432818 -95.368872)
		(width 0.12954)
		(layer "F.Cu")
		(net "FM_PLD_CLKS_DEV_EN")
	)
	(segment
		(start 251.951236 -93.88729)
		(end 251.951236 -93.584522)
		(width 0.12954)
		(layer "F.Cu")
		(net "FM_PLD_CLKS_DEV_EN")
	)
	(segment
		(start 269.13586 -92.870274)
		(end 268.024864 -92.870274)
		(width 0.12954)
		(layer "F.Cu")
		(net "FM_PLD_CLKS_DEV_EN")
	)
	(segment
		(start 252.335792 -91.021916)
		(end 252.335792 -92.24137)
		(width 0.12954)
		(layer "F.Cu")
		(net "FM_PLD_CLKS_DEV_EN")
	)
	(segment
		(start 267.38707 -92.23248)
		(end 263.320784 -88.166194)
		(width 0.12954)
		(layer "F.Cu")
		(net "FM_PLD_CLKS_DEV_EN")
	)
	(via
		(at 169.30624 -401.574)
		(size 0.508)
		(drill 0.254)
		(layers "F.Cu" "B.Cu")
		(net "FM_PLD_CLKS_DEV_EN")
	)
	(via
		(at 251.951236 -93.584522)
		(size 0.762)
		(drill 0.254)
		(layers "F.Cu" "B.Cu")
		(net "FM_PLD_CLKS_DEV_EN")
	)
	(via
		(at 236.65688 -133.314948)
		(size 0.508)
		(drill 0.254)
		(layers "F.Cu" "B.Cu")
		(net "FM_PLD_CLKS_DEV_EN")
	)
	(via
		(at 119.94388 -413.189928)
		(size 0.508)
		(drill 0.254)
		(layers "F.Cu" "B.Cu")
		(net "FM_PLD_CLKS_DEV_EN")
	)
	(via
		(at 219.91574 -132.552948)
		(size 0.508)
		(drill 0.254)
		(layers "F.Cu" "B.Cu")
		(net "FM_PLD_CLKS_DEV_EN")
	)
	(segment
		(start 235.05033 -133.031992)
		(end 236.373924 -133.031992)
		(width 0.12954)
		(layer "B.Cu")
		(net "FM_PLD_CLKS_DEV_EN")
	)
	(segment
		(start 234.08259 -132.875274)
		(end 233.971846 -132.875274)
		(width 0.12954)
		(layer "B.Cu")
		(net "FM_PLD_CLKS_DEV_EN")
	)
	(segment
		(start 236.373924 -133.031992)
		(end 236.65688 -133.314948)
		(width 0.12954)
		(layer "B.Cu")
		(net "FM_PLD_CLKS_DEV_EN")
	)
	(segment
		(start 234.889294 -132.870956)
		(end 234.875578 -132.85724)
		(width 0.12954)
		(layer "B.Cu")
		(net "FM_PLD_CLKS_DEV_EN")
	)
	(segment
		(start 234.875578 -132.85724)
		(end 234.100624 -132.85724)
		(width 0.12954)
		(layer "B.Cu")
		(net "FM_PLD_CLKS_DEV_EN")
	)
	(segment
		(start 234.100624 -132.85724)
		(end 234.08259 -132.875274)
		(width 0.12954)
		(layer "B.Cu")
		(net "FM_PLD_CLKS_DEV_EN")
	)
	(segment
		(start 234.889294 -132.870956)
		(end 235.05033 -133.031992)
		(width 0.12954)
		(layer "B.Cu")
		(net "FM_PLD_CLKS_DEV_EN")
	)
	(segment
		(start 170.1292 -394.249148)
		(end 170.1292 -388.947406)
		(width 0.127)
		(layer "In2.Cu")
		(net "FM_PLD_CLKS_DEV_EN")
	)
	(segment
		(start 247.14708 -101.107748)
		(end 248.50598 -99.748848)
		(width 0.127)
		(layer "In2.Cu")
		(net "FM_PLD_CLKS_DEV_EN")
	)
	(segment
		(start 169.15384 -399.839942)
		(end 169.15384 -395.224508)
		(width 0.127)
		(layer "In2.Cu")
		(net "FM_PLD_CLKS_DEV_EN")
	)
	(segment
		(start 227.46335 -146.953986)
		(end 219.91574 -139.406376)
		(width 0.127)
		(layer "In2.Cu")
		(net "FM_PLD_CLKS_DEV_EN")
	)
	(segment
		(start 241.38763 -128.746758)
		(end 241.38763 -121.462038)
		(width 0.127)
		(layer "In2.Cu")
		(net "FM_PLD_CLKS_DEV_EN")
	)
	(segment
		(start 225.3234 -237.921292)
		(end 229.4636 -233.781092)
		(width 0.127)
		(layer "In2.Cu")
		(net "FM_PLD_CLKS_DEV_EN")
	)
	(segment
		(start 227.46335 -215.379808)
		(end 227.46335 -146.953986)
		(width 0.127)
		(layer "In2.Cu")
		(net "FM_PLD_CLKS_DEV_EN")
	)
	(segment
		(start 170.1292 -388.947406)
		(end 170.212512 -388.864094)
		(width 0.127)
		(layer "In2.Cu")
		(net "FM_PLD_CLKS_DEV_EN")
	)
	(segment
		(start 170.212512 -388.564882)
		(end 225.3234 -333.453994)
		(width 0.127)
		(layer "In2.Cu")
		(net "FM_PLD_CLKS_DEV_EN")
	)
	(segment
		(start 169.255694 -400.39036)
		(end 169.2402 -400.30654)
		(width 0.127)
		(layer "In2.Cu")
		(net "FM_PLD_CLKS_DEV_EN")
	)
	(segment
		(start 229.4636 -217.380058)
		(end 227.46335 -215.379808)
		(width 0.127)
		(layer "In2.Cu")
		(net "FM_PLD_CLKS_DEV_EN")
	)
	(segment
		(start 236.65688 -133.314948)
		(end 240.46688 -133.314948)
		(width 0.127)
		(layer "In2.Cu")
		(net "FM_PLD_CLKS_DEV_EN")
	)
	(segment
		(start 251.755402 -93.388688)
		(end 251.951236 -93.584522)
		(width 0.127)
		(layer "In2.Cu")
		(net "FM_PLD_CLKS_DEV_EN")
	)
	(segment
		(start 241.38763 -121.462038)
		(end 247.14708 -115.702588)
		(width 0.127)
		(layer "In2.Cu")
		(net "FM_PLD_CLKS_DEV_EN")
	)
	(segment
		(start 250.57862 -96.487488)
		(end 250.57862 -93.732096)
		(width 0.127)
		(layer "In2.Cu")
		(net "FM_PLD_CLKS_DEV_EN")
	)
	(segment
		(start 247.14708 -115.702588)
		(end 247.14708 -101.107748)
		(width 0.127)
		(layer "In2.Cu")
		(net "FM_PLD_CLKS_DEV_EN")
	)
	(segment
		(start 250.922028 -93.388688)
		(end 251.755402 -93.388688)
		(width 0.127)
		(layer "In2.Cu")
		(net "FM_PLD_CLKS_DEV_EN")
	)
	(segment
		(start 241.58448 -132.197348)
		(end 241.58448 -128.943608)
		(width 0.127)
		(layer "In2.Cu")
		(net "FM_PLD_CLKS_DEV_EN")
	)
	(segment
		(start 249.36196 -98.501708)
		(end 250.07062 -97.793048)
		(width 0.127)
		(layer "In2.Cu")
		(net "FM_PLD_CLKS_DEV_EN")
	)
	(segment
		(start 241.58448 -128.943608)
		(end 241.38763 -128.746758)
		(width 0.127)
		(layer "In2.Cu")
		(net "FM_PLD_CLKS_DEV_EN")
	)
	(segment
		(start 248.50598 -98.870008)
		(end 248.87428 -98.501708)
		(width 0.127)
		(layer "In2.Cu")
		(net "FM_PLD_CLKS_DEV_EN")
	)
	(segment
		(start 240.46688 -133.314948)
		(end 241.58448 -132.197348)
		(width 0.127)
		(layer "In2.Cu")
		(net "FM_PLD_CLKS_DEV_EN")
	)
	(segment
		(start 169.2402 -400.30654)
		(end 169.15384 -399.839942)
		(width 0.127)
		(layer "In2.Cu")
		(net "FM_PLD_CLKS_DEV_EN")
	)
	(segment
		(start 248.87428 -98.501708)
		(end 249.36196 -98.501708)
		(width 0.127)
		(layer "In2.Cu")
		(net "FM_PLD_CLKS_DEV_EN")
	)
	(segment
		(start 170.212512 -388.864094)
		(end 170.212512 -388.564882)
		(width 0.127)
		(layer "In2.Cu")
		(net "FM_PLD_CLKS_DEV_EN")
	)
	(segment
		(start 250.07062 -97.793048)
		(end 250.07062 -96.995488)
		(width 0.127)
		(layer "In2.Cu")
		(net "FM_PLD_CLKS_DEV_EN")
	)
	(segment
		(start 250.57862 -93.732096)
		(end 250.922028 -93.388688)
		(width 0.127)
		(layer "In2.Cu")
		(net "FM_PLD_CLKS_DEV_EN")
	)
	(segment
		(start 169.30624 -401.574)
		(end 169.255694 -401.523454)
		(width 0.127)
		(layer "In2.Cu")
		(net "FM_PLD_CLKS_DEV_EN")
	)
	(segment
		(start 248.50598 -99.748848)
		(end 248.50598 -98.870008)
		(width 0.127)
		(layer "In2.Cu")
		(net "FM_PLD_CLKS_DEV_EN")
	)
	(segment
		(start 219.91574 -139.406376)
		(end 219.91574 -132.552948)
		(width 0.127)
		(layer "In2.Cu")
		(net "FM_PLD_CLKS_DEV_EN")
	)
	(segment
		(start 225.3234 -333.453994)
		(end 225.3234 -237.921292)
		(width 0.127)
		(layer "In2.Cu")
		(net "FM_PLD_CLKS_DEV_EN")
	)
	(segment
		(start 169.255694 -401.523454)
		(end 169.255694 -400.39036)
		(width 0.127)
		(layer "In2.Cu")
		(net "FM_PLD_CLKS_DEV_EN")
	)
	(segment
		(start 250.07062 -96.995488)
		(end 250.57862 -96.487488)
		(width 0.127)
		(layer "In2.Cu")
		(net "FM_PLD_CLKS_DEV_EN")
	)
	(segment
		(start 229.4636 -233.781092)
		(end 229.4636 -217.380058)
		(width 0.127)
		(layer "In2.Cu")
		(net "FM_PLD_CLKS_DEV_EN")
	)
	(segment
		(start 169.15384 -395.224508)
		(end 170.1292 -394.249148)
		(width 0.127)
		(layer "In2.Cu")
		(net "FM_PLD_CLKS_DEV_EN")
	)
	(segment
		(start 234.11688 -133.314948)
		(end 236.65688 -133.314948)
		(width 0.127)
		(layer "In4.Cu")
		(net "FM_PLD_CLKS_DEV_EN")
	)
	(segment
		(start 225.339148 -132.552948)
		(end 226.609148 -133.822948)
		(width 0.127)
		(layer "In4.Cu")
		(net "FM_PLD_CLKS_DEV_EN")
	)
	(segment
		(start 219.91574 -132.552948)
		(end 225.339148 -132.552948)
		(width 0.127)
		(layer "In4.Cu")
		(net "FM_PLD_CLKS_DEV_EN")
	)
	(segment
		(start 226.609148 -133.822948)
		(end 233.60888 -133.822948)
		(width 0.127)
		(layer "In4.Cu")
		(net "FM_PLD_CLKS_DEV_EN")
	)
	(segment
		(start 233.60888 -133.822948)
		(end 234.11688 -133.314948)
		(width 0.127)
		(layer "In4.Cu")
		(net "FM_PLD_CLKS_DEV_EN")
	)
	(segment
		(start 169.30624 -401.574)
		(end 168.139872 -402.740368)
		(width 0.127)
		(layer "In11.Cu")
		(net "FM_PLD_CLKS_DEV_EN")
	)
	(segment
		(start 119.64416 -413.189928)
		(end 119.94388 -413.189928)
		(width 0.127)
		(layer "In11.Cu")
		(net "FM_PLD_CLKS_DEV_EN")
	)
	(segment
		(start 119.61368 -402.740368)
		(end 118.11508 -404.238968)
		(width 0.127)
		(layer "In11.Cu")
		(net "FM_PLD_CLKS_DEV_EN")
	)
	(segment
		(start 118.11508 -404.238968)
		(end 118.11508 -411.660848)
		(width 0.127)
		(layer "In11.Cu")
		(net "FM_PLD_CLKS_DEV_EN")
	)
	(segment
		(start 118.11508 -411.660848)
		(end 119.64416 -413.189928)
		(width 0.127)
		(layer "In11.Cu")
		(net "FM_PLD_CLKS_DEV_EN")
	)
	(segment
		(start 168.139872 -402.740368)
		(end 119.61368 -402.740368)
		(width 0.127)
		(layer "In11.Cu")
		(net "FM_PLD_CLKS_DEV_EN")
	)
	(segment
		(start 174.04588 -129.866898)
		(end 174.04588 -129.250948)
		(width 0.12954)
		(layer "F.Cu")
		(net "FM_PFR_DSW_PWROK_N")
	)
	(segment
		(start 209.34553 -133.878828)
		(end 208.71688 -133.878828)
		(width 0.12954)
		(layer "F.Cu")
		(net "FM_PFR_DSW_PWROK_N")
	)
	(segment
		(start 175.755554 -117.775482)
		(end 175.355504 -118.175532)
		(width 0.12954)
		(layer "F.Cu")
		(net "FM_PFR_DSW_PWROK_N")
	)
	(via
		(at 174.04588 -129.250948)
		(size 0.508)
		(drill 0.254)
		(layers "F.Cu" "B.Cu")
		(net "FM_PFR_DSW_PWROK_N")
	)
	(via
		(at 175.355504 -118.175532)
		(size 0.4572)
		(drill 0.254)
		(layers "F.Cu" "B.Cu")
		(net "FM_PFR_DSW_PWROK_N")
	)
	(via
		(at 208.71688 -133.878828)
		(size 0.508)
		(drill 0.254)
		(layers "F.Cu" "B.Cu")
		(net "FM_PFR_DSW_PWROK_N")
	)
	(segment
		(start 174.95012 -121.717308)
		(end 174.95012 -118.783608)
		(width 0.127)
		(layer "In2.Cu")
		(net "FM_PFR_DSW_PWROK_N")
	)
	(segment
		(start 173.33468 -125.755908)
		(end 172.98162 -125.402848)
		(width 0.127)
		(layer "In2.Cu")
		(net "FM_PFR_DSW_PWROK_N")
	)
	(segment
		(start 174.95012 -118.783608)
		(end 175.355504 -118.378224)
		(width 0.127)
		(layer "In2.Cu")
		(net "FM_PFR_DSW_PWROK_N")
	)
	(segment
		(start 174.74438 -121.923048)
		(end 174.95012 -121.717308)
		(width 0.127)
		(layer "In2.Cu")
		(net "FM_PFR_DSW_PWROK_N")
	)
	(segment
		(start 174.04588 -129.250948)
		(end 173.33468 -128.539748)
		(width 0.127)
		(layer "In2.Cu")
		(net "FM_PFR_DSW_PWROK_N")
	)
	(segment
		(start 174.1043 -121.923048)
		(end 174.74438 -121.923048)
		(width 0.127)
		(layer "In2.Cu")
		(net "FM_PFR_DSW_PWROK_N")
	)
	(segment
		(start 172.98162 -123.045728)
		(end 174.1043 -121.923048)
		(width 0.127)
		(layer "In2.Cu")
		(net "FM_PFR_DSW_PWROK_N")
	)
	(segment
		(start 172.98162 -125.402848)
		(end 172.98162 -123.045728)
		(width 0.127)
		(layer "In2.Cu")
		(net "FM_PFR_DSW_PWROK_N")
	)
	(segment
		(start 175.355504 -118.378224)
		(end 175.355504 -118.175532)
		(width 0.127)
		(layer "In2.Cu")
		(net "FM_PFR_DSW_PWROK_N")
	)
	(segment
		(start 173.33468 -128.539748)
		(end 173.33468 -125.755908)
		(width 0.127)
		(layer "In2.Cu")
		(net "FM_PFR_DSW_PWROK_N")
	)
	(segment
		(start 187.9092 -128.032002)
		(end 187.9092 -128.4732)
		(width 0.127)
		(layer "In4.Cu")
		(net "FM_PFR_DSW_PWROK_N")
	)
	(segment
		(start 187.375546 -127.498348)
		(end 187.9092 -128.032002)
		(width 0.127)
		(layer "In4.Cu")
		(net "FM_PFR_DSW_PWROK_N")
	)
	(segment
		(start 177.68316 -129.804668)
		(end 179.2859 -129.804668)
		(width 0.127)
		(layer "In4.Cu")
		(net "FM_PFR_DSW_PWROK_N")
	)
	(segment
		(start 174.04588 -129.250948)
		(end 174.60468 -129.809748)
		(width 0.127)
		(layer "In4.Cu")
		(net "FM_PFR_DSW_PWROK_N")
	)
	(segment
		(start 179.2859 -129.804668)
		(end 180.33492 -128.755648)
		(width 0.127)
		(layer "In4.Cu")
		(net "FM_PFR_DSW_PWROK_N")
	)
	(segment
		(start 180.33492 -128.755648)
		(end 183.66486 -128.755648)
		(width 0.127)
		(layer "In4.Cu")
		(net "FM_PFR_DSW_PWROK_N")
	)
	(segment
		(start 198.99376 -133.878828)
		(end 208.71688 -133.878828)
		(width 0.127)
		(layer "In4.Cu")
		(net "FM_PFR_DSW_PWROK_N")
	)
	(segment
		(start 174.60468 -129.809748)
		(end 177.67808 -129.809748)
		(width 0.127)
		(layer "In4.Cu")
		(net "FM_PFR_DSW_PWROK_N")
	)
	(segment
		(start 184.92216 -127.498348)
		(end 187.375546 -127.498348)
		(width 0.127)
		(layer "In4.Cu")
		(net "FM_PFR_DSW_PWROK_N")
	)
	(segment
		(start 187.9092 -128.4732)
		(end 190.190628 -130.754628)
		(width 0.127)
		(layer "In4.Cu")
		(net "FM_PFR_DSW_PWROK_N")
	)
	(segment
		(start 190.190628 -130.754628)
		(end 195.86956 -130.754628)
		(width 0.127)
		(layer "In4.Cu")
		(net "FM_PFR_DSW_PWROK_N")
	)
	(segment
		(start 195.86956 -130.754628)
		(end 198.99376 -133.878828)
		(width 0.127)
		(layer "In4.Cu")
		(net "FM_PFR_DSW_PWROK_N")
	)
	(segment
		(start 183.66486 -128.755648)
		(end 184.92216 -127.498348)
		(width 0.127)
		(layer "In4.Cu")
		(net "FM_PFR_DSW_PWROK_N")
	)
	(segment
		(start 177.67808 -129.809748)
		(end 177.68316 -129.804668)
		(width 0.127)
		(layer "In4.Cu")
		(net "FM_PFR_DSW_PWROK_N")
	)
	(segment
		(start 111.640112 -234.69219)
		(end 111.640366 -234.691936)
		(width 0.12954)
		(layer "F.Cu")
		(net "FM_PEHPCPU1_ALERT_N")
	)
	(segment
		(start 111.640366 -234.691936)
		(end 111.640366 -234.15625)
		(width 0.12954)
		(layer "F.Cu")
		(net "FM_PEHPCPU1_ALERT_N")
	)
	(via
		(at 111.640366 -234.15625)
		(size 0.4572)
		(drill 0.2032)
		(layers "F.Cu" "B.Cu")
		(net "FM_PEHPCPU1_ALERT_N")
	)
	(via
		(at 86.762336 -211.347558)
		(size 0.6604)
		(drill 0.3302)
		(layers "F.Cu" "B.Cu")
		(net "FM_PEHPCPU1_ALERT_N")
	)
	(segment
		(start 86.234778 -219.15501)
		(end 85.848444 -219.15501)
		(width 0.12954)
		(layer "B.Cu")
		(net "FM_PEHPCPU1_ALERT_N")
	)
	(segment
		(start 107.6071 -226.511866)
		(end 107.59821 -226.506786)
		(width 0.0889)
		(layer "B.Cu")
		(net "FM_PEHPCPU1_ALERT_N")
	)
	(segment
		(start 90.44178 -182.400448)
		(end 89.99347 -182.400448)
		(width 0.12954)
		(layer "B.Cu")
		(net "FM_PEHPCPU1_ALERT_N")
	)
	(segment
		(start 92.657168 -220.809566)
		(end 92.648278 -220.814646)
		(width 0.0889)
		(layer "B.Cu")
		(net "FM_PEHPCPU1_ALERT_N")
	)
	(segment
		(start 105.257854 -222.442278)
		(end 105.248964 -222.437198)
		(width 0.0889)
		(layer "B.Cu")
		(net "FM_PEHPCPU1_ALERT_N")
	)
	(segment
		(start 103.464614 -221.623382)
		(end 103.449882 -221.632018)
		(width 0.0889)
		(layer "B.Cu")
		(net "FM_PEHPCPU1_ALERT_N")
	)
	(segment
		(start 91.339416 -221.149418)
		(end 91.339416 -221.133924)
		(width 0.0889)
		(layer "B.Cu")
		(net "FM_PEHPCPU1_ALERT_N")
	)
	(segment
		(start 95.098616 -221.149418)
		(end 95.098616 -221.133924)
		(width 0.0889)
		(layer "B.Cu")
		(net "FM_PEHPCPU1_ALERT_N")
	)
	(segment
		(start 94.536768 -220.809566)
		(end 94.527878 -220.814646)
		(width 0.0889)
		(layer "B.Cu")
		(net "FM_PEHPCPU1_ALERT_N")
	)
	(segment
		(start 104.309164 -222.437198)
		(end 104.303068 -222.433642)
		(width 0.0889)
		(layer "B.Cu")
		(net "FM_PEHPCPU1_ALERT_N")
	)
	(segment
		(start 105.7275 -223.256348)
		(end 105.71861 -223.251268)
		(width 0.0889)
		(layer "B.Cu")
		(net "FM_PEHPCPU1_ALERT_N")
	)
	(segment
		(start 110.605062 -231.714548)
		(end 110.605062 -231.705912)
		(width 0.0889)
		(layer "B.Cu")
		(net "FM_PEHPCPU1_ALERT_N")
	)
	(segment
		(start 90.777568 -220.809566)
		(end 90.768678 -220.814646)
		(width 0.0889)
		(layer "B.Cu")
		(net "FM_PEHPCPU1_ALERT_N")
	)
	(segment
		(start 90.307922 -203.115926)
		(end 90.307922 -192.861946)
		(width 0.12954)
		(layer "B.Cu")
		(net "FM_PEHPCPU1_ALERT_N")
	)
	(segment
		(start 99.705414 -221.623382)
		(end 99.690682 -221.632018)
		(width 0.0889)
		(layer "B.Cu")
		(net "FM_PEHPCPU1_ALERT_N")
	)
	(segment
		(start 90.8939 -185.575448)
		(end 90.8939 -184.100216)
		(width 0.12954)
		(layer "B.Cu")
		(net "FM_PEHPCPU1_ALERT_N")
	)
	(segment
		(start 105.436416 -222.783654)
		(end 105.436416 -222.761556)
		(width 0.0889)
		(layer "B.Cu")
		(net "FM_PEHPCPU1_ALERT_N")
	)
	(segment
		(start 101.59111 -221.619826)
		(end 101.585014 -221.623382)
		(width 0.0889)
		(layer "B.Cu")
		(net "FM_PEHPCPU1_ALERT_N")
	)
	(segment
		(start 108.077254 -228.953568)
		(end 108.068364 -228.948488)
		(width 0.0889)
		(layer "B.Cu")
		(net "FM_PEHPCPU1_ALERT_N")
	)
	(segment
		(start 101.585014 -221.623382)
		(end 101.570282 -221.632018)
		(width 0.0889)
		(layer "B.Cu")
		(net "FM_PEHPCPU1_ALERT_N")
	)
	(segment
		(start 103.8479 -221.628462)
		(end 103.83901 -221.623382)
		(width 0.0889)
		(layer "B.Cu")
		(net "FM_PEHPCPU1_ALERT_N")
	)
	(segment
		(start 111.640366 -234.15625)
		(end 111.79683 -233.885232)
		(width 0.0889)
		(layer "B.Cu")
		(net "FM_PEHPCPU1_ALERT_N")
	)
	(segment
		(start 107.6071 -228.139752)
		(end 107.59821 -228.134672)
		(width 0.0889)
		(layer "B.Cu")
		(net "FM_PEHPCPU1_ALERT_N")
	)
	(segment
		(start 88.215724 -220.71965)
		(end 88.093804 -220.59773)
		(width 0.0889)
		(layer "B.Cu")
		(net "FM_PEHPCPU1_ALERT_N")
	)
	(segment
		(start 90.148664 -208.666334)
		(end 91.49588 -207.319118)
		(width 0.12954)
		(layer "B.Cu")
		(net "FM_PEHPCPU1_ALERT_N")
	)
	(segment
		(start 100.558854 -220.814646)
		(end 100.549964 -220.809566)
		(width 0.0889)
		(layer "B.Cu")
		(net "FM_PEHPCPU1_ALERT_N")
	)
	(segment
		(start 95.95231 -221.619826)
		(end 95.946214 -221.623382)
		(width 0.0889)
		(layer "B.Cu")
		(net "FM_PEHPCPU1_ALERT_N")
	)
	(segment
		(start 110.896654 -232.209086)
		(end 110.887764 -232.204006)
		(width 0.0889)
		(layer "B.Cu")
		(net "FM_PEHPCPU1_ALERT_N")
	)
	(segment
		(start 84.845398 -218.151964)
		(end 84.845398 -213.264496)
		(width 0.12954)
		(layer "B.Cu")
		(net "FM_PEHPCPU1_ALERT_N")
	)
	(segment
		(start 109.4867 -229.767384)
		(end 109.47781 -229.762304)
		(width 0.0889)
		(layer "B.Cu")
		(net "FM_PEHPCPU1_ALERT_N")
	)
	(segment
		(start 90.54338 -183.483504)
		(end 90.54338 -182.502048)
		(width 0.12954)
		(layer "B.Cu")
		(net "FM_PEHPCPU1_ALERT_N")
	)
	(segment
		(start 106.6673 -224.88398)
		(end 106.65841 -224.8789)
		(width 0.0889)
		(layer "B.Cu")
		(net "FM_PEHPCPU1_ALERT_N")
	)
	(segment
		(start 110.135162 -230.908098)
		(end 110.135162 -230.900478)
		(width 0.0889)
		(layer "B.Cu")
		(net "FM_PEHPCPU1_ALERT_N")
	)
	(segment
		(start 111.544862 -233.356404)
		(end 111.544862 -233.34218)
		(width 0.0889)
		(layer "B.Cu")
		(net "FM_PEHPCPU1_ALERT_N")
	)
	(segment
		(start 86.762336 -211.347558)
		(end 89.44356 -208.666334)
		(width 0.12954)
		(layer "B.Cu")
		(net "FM_PEHPCPU1_ALERT_N")
	)
	(segment
		(start 97.83191 -221.619826)
		(end 97.825814 -221.623382)
		(width 0.0889)
		(layer "B.Cu")
		(net "FM_PEHPCPU1_ALERT_N")
	)
	(segment
		(start 90.442288 -186.02706)
		(end 90.8939 -185.575448)
		(width 0.12954)
		(layer "B.Cu")
		(net "FM_PEHPCPU1_ALERT_N")
	)
	(segment
		(start 106.197654 -224.070164)
		(end 106.188764 -224.065084)
		(width 0.0889)
		(layer "B.Cu")
		(net "FM_PEHPCPU1_ALERT_N")
	)
	(segment
		(start 107.316016 -227.667058)
		(end 107.316016 -227.629466)
		(width 0.0889)
		(layer "B.Cu")
		(net "FM_PEHPCPU1_ALERT_N")
	)
	(segment
		(start 106.845862 -225.217482)
		(end 106.845862 -225.203258)
		(width 0.0889)
		(layer "B.Cu")
		(net "FM_PEHPCPU1_ALERT_N")
	)
	(segment
		(start 91.160854 -220.814646)
		(end 91.151964 -220.809566)
		(width 0.0889)
		(layer "B.Cu")
		(net "FM_PEHPCPU1_ALERT_N")
	)
	(segment
		(start 92.187014 -221.623382)
		(end 92.172282 -221.632018)
		(width 0.0889)
		(layer "B.Cu")
		(net "FM_PEHPCPU1_ALERT_N")
	)
	(segment
		(start 90.31351 -221.619826)
		(end 90.307414 -221.623382)
		(width 0.0889)
		(layer "B.Cu")
		(net "FM_PEHPCPU1_ALERT_N")
	)
	(segment
		(start 94.920054 -220.814646)
		(end 94.911164 -220.809566)
		(width 0.0889)
		(layer "B.Cu")
		(net "FM_PEHPCPU1_ALERT_N")
	)
	(segment
		(start 109.103414 -229.762304)
		(end 109.088682 -229.77094)
		(width 0.0889)
		(layer "B.Cu")
		(net "FM_PEHPCPU1_ALERT_N")
	)
	(segment
		(start 106.188764 -224.065084)
		(end 106.176572 -224.057972)
		(width 0.0889)
		(layer "B.Cu")
		(net "FM_PEHPCPU1_ALERT_N")
	)
	(segment
		(start 108.068364 -228.948488)
		(end 108.062268 -228.944932)
		(width 0.0889)
		(layer "B.Cu")
		(net "FM_PEHPCPU1_ALERT_N")
	)
	(segment
		(start 102.055168 -220.809566)
		(end 102.046278 -220.814646)
		(width 0.0889)
		(layer "B.Cu")
		(net "FM_PEHPCPU1_ALERT_N")
	)
	(segment
		(start 109.665262 -230.102156)
		(end 109.665262 -230.086662)
		(width 0.0889)
		(layer "B.Cu")
		(net "FM_PEHPCPU1_ALERT_N")
	)
	(segment
		(start 107.59821 -227.155502)
		(end 107.6071 -227.150422)
		(width 0.0889)
		(layer "B.Cu")
		(net "FM_PEHPCPU1_ALERT_N")
	)
	(segment
		(start 87.677498 -220.59773)
		(end 87.443818 -220.36405)
		(width 0.0889)
		(layer "B.Cu")
		(net "FM_PEHPCPU1_ALERT_N")
	)
	(segment
		(start 90.442288 -192.72758)
		(end 90.442288 -186.02706)
		(width 0.12954)
		(layer "B.Cu")
		(net "FM_PEHPCPU1_ALERT_N")
	)
	(segment
		(start 108.255816 -229.28834)
		(end 108.255816 -229.272846)
		(width 0.0889)
		(layer "B.Cu")
		(net "FM_PEHPCPU1_ALERT_N")
	)
	(segment
		(start 94.066614 -221.623382)
		(end 94.051882 -221.632018)
		(width 0.0889)
		(layer "B.Cu")
		(net "FM_PEHPCPU1_ALERT_N")
	)
	(segment
		(start 111.79683 -233.885232)
		(end 111.7727 -233.796078)
		(width 0.0889)
		(layer "B.Cu")
		(net "FM_PEHPCPU1_ALERT_N")
	)
	(segment
		(start 107.137454 -225.69805)
		(end 107.128564 -225.69297)
		(width 0.0889)
		(layer "B.Cu")
		(net "FM_PEHPCPU1_ALERT_N")
	)
	(segment
		(start 89.44356 -208.666334)
		(end 90.148664 -208.666334)
		(width 0.12954)
		(layer "B.Cu")
		(net "FM_PEHPCPU1_ALERT_N")
	)
	(segment
		(start 88.093804 -220.59773)
		(end 87.677498 -220.59773)
		(width 0.0889)
		(layer "B.Cu")
		(net "FM_PEHPCPU1_ALERT_N")
	)
	(segment
		(start 90.8939 -184.100216)
		(end 90.410284 -183.6166)
		(width 0.12954)
		(layer "B.Cu")
		(net "FM_PEHPCPU1_ALERT_N")
	)
	(segment
		(start 93.219016 -221.149418)
		(end 93.219016 -221.133924)
		(width 0.0889)
		(layer "B.Cu")
		(net "FM_PEHPCPU1_ALERT_N")
	)
	(segment
		(start 92.19311 -221.619826)
		(end 92.187014 -221.623382)
		(width 0.0889)
		(layer "B.Cu")
		(net "FM_PEHPCPU1_ALERT_N")
	)
	(segment
		(start 93.040454 -220.814646)
		(end 93.031564 -220.809566)
		(width 0.0889)
		(layer "B.Cu")
		(net "FM_PEHPCPU1_ALERT_N")
	)
	(segment
		(start 104.323896 -222.445834)
		(end 104.309164 -222.437198)
		(width 0.0889)
		(layer "B.Cu")
		(net "FM_PEHPCPU1_ALERT_N")
	)
	(segment
		(start 84.845398 -213.264496)
		(end 86.762336 -211.347558)
		(width 0.12954)
		(layer "B.Cu")
		(net "FM_PEHPCPU1_ALERT_N")
	)
	(segment
		(start 98.679254 -220.814646)
		(end 98.678238 -220.814138)
		(width 0.0889)
		(layer "B.Cu")
		(net "FM_PEHPCPU1_ALERT_N")
	)
	(segment
		(start 98.678238 -220.814138)
		(end 98.670364 -220.809566)
		(width 0.0889)
		(layer "B.Cu")
		(net "FM_PEHPCPU1_ALERT_N")
	)
	(segment
		(start 109.962442 -230.584756)
		(end 109.947456 -230.57612)
		(width 0.0889)
		(layer "B.Cu")
		(net "FM_PEHPCPU1_ALERT_N")
	)
	(segment
		(start 89.281254 -220.814646)
		(end 89.272364 -220.809566)
		(width 0.0889)
		(layer "B.Cu")
		(net "FM_PEHPCPU1_ALERT_N")
	)
	(segment
		(start 96.799654 -220.814646)
		(end 96.790764 -220.809566)
		(width 0.0889)
		(layer "B.Cu")
		(net "FM_PEHPCPU1_ALERT_N")
	)
	(segment
		(start 90.307414 -221.623382)
		(end 90.292682 -221.632018)
		(width 0.0889)
		(layer "B.Cu")
		(net "FM_PEHPCPU1_ALERT_N")
	)
	(segment
		(start 91.49588 -204.303884)
		(end 90.307922 -203.115926)
		(width 0.12954)
		(layer "B.Cu")
		(net "FM_PEHPCPU1_ALERT_N")
	)
	(segment
		(start 95.946214 -221.623382)
		(end 95.931482 -221.632018)
		(width 0.0889)
		(layer "B.Cu")
		(net "FM_PEHPCPU1_ALERT_N")
	)
	(segment
		(start 96.416368 -220.809566)
		(end 96.407478 -220.814646)
		(width 0.0889)
		(layer "B.Cu")
		(net "FM_PEHPCPU1_ALERT_N")
	)
	(segment
		(start 99.71151 -221.619826)
		(end 99.705414 -221.623382)
		(width 0.0889)
		(layer "B.Cu")
		(net "FM_PEHPCPU1_ALERT_N")
	)
	(segment
		(start 102.617016 -221.149418)
		(end 102.617016 -221.133924)
		(width 0.0889)
		(layer "B.Cu")
		(net "FM_PEHPCPU1_ALERT_N")
	)
	(segment
		(start 111.075216 -232.543858)
		(end 111.075216 -232.528364)
		(width 0.0889)
		(layer "B.Cu")
		(net "FM_PEHPCPU1_ALERT_N")
	)
	(segment
		(start 100.737416 -221.149418)
		(end 100.737416 -221.133924)
		(width 0.0889)
		(layer "B.Cu")
		(net "FM_PEHPCPU1_ALERT_N")
	)
	(segment
		(start 107.316016 -226.032822)
		(end 107.316016 -226.017328)
		(width 0.0889)
		(layer "B.Cu")
		(net "FM_PEHPCPU1_ALERT_N")
	)
	(segment
		(start 87.443818 -220.36405)
		(end 86.234778 -219.15501)
		(width 0.12954)
		(layer "B.Cu")
		(net "FM_PEHPCPU1_ALERT_N")
	)
	(segment
		(start 98.857816 -221.149418)
		(end 98.857816 -221.133924)
		(width 0.0889)
		(layer "B.Cu")
		(net "FM_PEHPCPU1_ALERT_N")
	)
	(segment
		(start 90.410284 -183.6166)
		(end 90.54338 -183.483504)
		(width 0.12954)
		(layer "B.Cu")
		(net "FM_PEHPCPU1_ALERT_N")
	)
	(segment
		(start 85.848444 -219.15501)
		(end 84.845398 -218.151964)
		(width 0.12954)
		(layer "B.Cu")
		(net "FM_PEHPCPU1_ALERT_N")
	)
	(segment
		(start 111.3663 -233.022902)
		(end 111.35741 -233.017822)
		(width 0.0889)
		(layer "B.Cu")
		(net "FM_PEHPCPU1_ALERT_N")
	)
	(segment
		(start 96.978216 -221.149418)
		(end 96.978216 -221.133924)
		(width 0.0889)
		(layer "B.Cu")
		(net "FM_PEHPCPU1_ALERT_N")
	)
	(segment
		(start 102.438454 -220.814646)
		(end 102.429564 -220.809566)
		(width 0.0889)
		(layer "B.Cu")
		(net "FM_PEHPCPU1_ALERT_N")
	)
	(segment
		(start 100.175568 -220.809566)
		(end 100.166678 -220.814646)
		(width 0.0889)
		(layer "B.Cu")
		(net "FM_PEHPCPU1_ALERT_N")
	)
	(segment
		(start 110.887764 -232.204006)
		(end 110.881668 -232.20045)
		(width 0.0889)
		(layer "B.Cu")
		(net "FM_PEHPCPU1_ALERT_N")
	)
	(segment
		(start 97.825814 -221.623382)
		(end 97.811082 -221.632018)
		(width 0.0889)
		(layer "B.Cu")
		(net "FM_PEHPCPU1_ALERT_N")
	)
	(segment
		(start 98.295968 -220.809566)
		(end 98.287078 -220.814646)
		(width 0.0889)
		(layer "B.Cu")
		(net "FM_PEHPCPU1_ALERT_N")
	)
	(segment
		(start 94.07271 -221.619826)
		(end 94.066614 -221.623382)
		(width 0.0889)
		(layer "B.Cu")
		(net "FM_PEHPCPU1_ALERT_N")
	)
	(segment
		(start 91.49588 -207.319118)
		(end 91.49588 -204.303884)
		(width 0.12954)
		(layer "B.Cu")
		(net "FM_PEHPCPU1_ALERT_N")
	)
	(segment
		(start 89.459816 -221.149418)
		(end 89.459816 -221.133924)
		(width 0.0889)
		(layer "B.Cu")
		(net "FM_PEHPCPU1_ALERT_N")
	)
	(segment
		(start 106.376216 -224.404936)
		(end 106.376216 -224.389442)
		(width 0.0889)
		(layer "B.Cu")
		(net "FM_PEHPCPU1_ALERT_N")
	)
	(segment
		(start 90.307922 -192.861946)
		(end 90.442288 -192.72758)
		(width 0.12954)
		(layer "B.Cu")
		(net "FM_PEHPCPU1_ALERT_N")
	)
	(segment
		(start 90.54338 -182.502048)
		(end 90.44178 -182.400448)
		(width 0.12954)
		(layer "B.Cu")
		(net "FM_PEHPCPU1_ALERT_N")
	)
	(arc
		(start 106.176572 -224.057972)
		(mid 105.978344 -223.852124)
		(end 105.906062 -223.575626)
		(width 0.0889)
		(layer "B.Cu")
		(net "FM_PEHPCPU1_ALERT_N")
	)
	(arc
		(start 93.031564 -220.809566)
		(mid 92.844366 -220.759423)
		(end 92.657168 -220.809566)
		(width 0.0889)
		(layer "B.Cu")
		(net "FM_PEHPCPU1_ALERT_N")
	)
	(arc
		(start 105.906062 -223.575626)
		(mid 105.858383 -223.392726)
		(end 105.7275 -223.256348)
		(width 0.0889)
		(layer "B.Cu")
		(net "FM_PEHPCPU1_ALERT_N")
	)
	(arc
		(start 101.867716 -221.133924)
		(mid 101.793725 -221.41349)
		(end 101.59111 -221.619826)
		(width 0.0889)
		(layer "B.Cu")
		(net "FM_PEHPCPU1_ALERT_N")
	)
	(arc
		(start 102.617016 -221.133924)
		(mid 102.569337 -220.951024)
		(end 102.438454 -220.814646)
		(width 0.0889)
		(layer "B.Cu")
		(net "FM_PEHPCPU1_ALERT_N")
	)
	(arc
		(start 104.303068 -222.433642)
		(mid 104.100481 -222.227291)
		(end 104.026462 -221.94774)
		(width 0.0889)
		(layer "B.Cu")
		(net "FM_PEHPCPU1_ALERT_N")
	)
	(arc
		(start 107.59821 -228.134672)
		(mid 107.396928 -227.937185)
		(end 107.316016 -227.667058)
		(width 0.0889)
		(layer "B.Cu")
		(net "FM_PEHPCPU1_ALERT_N")
	)
	(arc
		(start 92.648278 -220.814646)
		(mid 92.517364 -220.951006)
		(end 92.469716 -221.133924)
		(width 0.0889)
		(layer "B.Cu")
		(net "FM_PEHPCPU1_ALERT_N")
	)
	(arc
		(start 91.62161 -221.623382)
		(mid 91.418787 -221.423151)
		(end 91.339416 -221.149418)
		(width 0.0889)
		(layer "B.Cu")
		(net "FM_PEHPCPU1_ALERT_N")
	)
	(arc
		(start 90.768678 -220.814646)
		(mid 90.637764 -220.951006)
		(end 90.590116 -221.133924)
		(width 0.0889)
		(layer "B.Cu")
		(net "FM_PEHPCPU1_ALERT_N")
	)
	(arc
		(start 106.65841 -224.8789)
		(mid 106.455587 -224.678669)
		(end 106.376216 -224.404936)
		(width 0.0889)
		(layer "B.Cu")
		(net "FM_PEHPCPU1_ALERT_N")
	)
	(arc
		(start 98.670364 -220.809566)
		(mid 98.483166 -220.759423)
		(end 98.295968 -220.809566)
		(width 0.0889)
		(layer "B.Cu")
		(net "FM_PEHPCPU1_ALERT_N")
	)
	(arc
		(start 102.429564 -220.809566)
		(mid 102.242366 -220.759423)
		(end 102.055168 -220.809566)
		(width 0.0889)
		(layer "B.Cu")
		(net "FM_PEHPCPU1_ALERT_N")
	)
	(arc
		(start 98.287078 -220.814646)
		(mid 98.156164 -220.951006)
		(end 98.108516 -221.133924)
		(width 0.0889)
		(layer "B.Cu")
		(net "FM_PEHPCPU1_ALERT_N")
	)
	(arc
		(start 111.35741 -233.017822)
		(mid 111.154587 -232.817591)
		(end 111.075216 -232.543858)
		(width 0.0889)
		(layer "B.Cu")
		(net "FM_PEHPCPU1_ALERT_N")
	)
	(arc
		(start 98.108516 -221.133924)
		(mid 98.034525 -221.41349)
		(end 97.83191 -221.619826)
		(width 0.0889)
		(layer "B.Cu")
		(net "FM_PEHPCPU1_ALERT_N")
	)
	(arc
		(start 105.436416 -222.761556)
		(mid 105.388737 -222.578656)
		(end 105.257854 -222.442278)
		(width 0.0889)
		(layer "B.Cu")
		(net "FM_PEHPCPU1_ALERT_N")
	)
	(arc
		(start 101.570282 -221.632018)
		(mid 101.293807 -221.699338)
		(end 101.01961 -221.623382)
		(width 0.0889)
		(layer "B.Cu")
		(net "FM_PEHPCPU1_ALERT_N")
	)
	(arc
		(start 90.292682 -221.632018)
		(mid 90.016207 -221.699338)
		(end 89.74201 -221.623382)
		(width 0.0889)
		(layer "B.Cu")
		(net "FM_PEHPCPU1_ALERT_N")
	)
	(arc
		(start 92.172282 -221.632018)
		(mid 91.895807 -221.699338)
		(end 91.62161 -221.623382)
		(width 0.0889)
		(layer "B.Cu")
		(net "FM_PEHPCPU1_ALERT_N")
	)
	(arc
		(start 109.088682 -229.77094)
		(mid 108.812207 -229.83826)
		(end 108.53801 -229.762304)
		(width 0.0889)
		(layer "B.Cu")
		(net "FM_PEHPCPU1_ALERT_N")
	)
	(arc
		(start 107.316016 -226.017328)
		(mid 107.268337 -225.834428)
		(end 107.137454 -225.69805)
		(width 0.0889)
		(layer "B.Cu")
		(net "FM_PEHPCPU1_ALERT_N")
	)
	(arc
		(start 103.83901 -221.623382)
		(mid 103.651812 -221.573239)
		(end 103.464614 -221.623382)
		(width 0.0889)
		(layer "B.Cu")
		(net "FM_PEHPCPU1_ALERT_N")
	)
	(arc
		(start 96.978216 -221.133924)
		(mid 96.930537 -220.951024)
		(end 96.799654 -220.814646)
		(width 0.0889)
		(layer "B.Cu")
		(net "FM_PEHPCPU1_ALERT_N")
	)
	(arc
		(start 94.527878 -220.814646)
		(mid 94.396964 -220.951006)
		(end 94.349316 -221.133924)
		(width 0.0889)
		(layer "B.Cu")
		(net "FM_PEHPCPU1_ALERT_N")
	)
	(arc
		(start 89.459816 -221.133924)
		(mid 89.412137 -220.951024)
		(end 89.281254 -220.814646)
		(width 0.0889)
		(layer "B.Cu")
		(net "FM_PEHPCPU1_ALERT_N")
	)
	(arc
		(start 108.255816 -229.272846)
		(mid 108.208137 -229.089946)
		(end 108.077254 -228.953568)
		(width 0.0889)
		(layer "B.Cu")
		(net "FM_PEHPCPU1_ALERT_N")
	)
	(arc
		(start 99.988116 -221.133924)
		(mid 99.914125 -221.41349)
		(end 99.71151 -221.619826)
		(width 0.0889)
		(layer "B.Cu")
		(net "FM_PEHPCPU1_ALERT_N")
	)
	(arc
		(start 100.549964 -220.809566)
		(mid 100.362766 -220.759423)
		(end 100.175568 -220.809566)
		(width 0.0889)
		(layer "B.Cu")
		(net "FM_PEHPCPU1_ALERT_N")
	)
	(arc
		(start 95.38081 -221.623382)
		(mid 95.177987 -221.423151)
		(end 95.098616 -221.149418)
		(width 0.0889)
		(layer "B.Cu")
		(net "FM_PEHPCPU1_ALERT_N")
	)
	(arc
		(start 92.469716 -221.133924)
		(mid 92.395725 -221.41349)
		(end 92.19311 -221.619826)
		(width 0.0889)
		(layer "B.Cu")
		(net "FM_PEHPCPU1_ALERT_N")
	)
	(arc
		(start 100.737416 -221.133924)
		(mid 100.689737 -220.951024)
		(end 100.558854 -220.814646)
		(width 0.0889)
		(layer "B.Cu")
		(net "FM_PEHPCPU1_ALERT_N")
	)
	(arc
		(start 89.74201 -221.623382)
		(mid 89.539187 -221.423151)
		(end 89.459816 -221.149418)
		(width 0.0889)
		(layer "B.Cu")
		(net "FM_PEHPCPU1_ALERT_N")
	)
	(arc
		(start 88.897968 -220.809566)
		(mid 88.615266 -220.885308)
		(end 88.332564 -220.809566)
		(width 0.0889)
		(layer "B.Cu")
		(net "FM_PEHPCPU1_ALERT_N")
	)
	(arc
		(start 107.59821 -226.506786)
		(mid 107.395387 -226.306555)
		(end 107.316016 -226.032822)
		(width 0.0889)
		(layer "B.Cu")
		(net "FM_PEHPCPU1_ALERT_N")
	)
	(arc
		(start 102.89921 -221.623382)
		(mid 102.696387 -221.423151)
		(end 102.617016 -221.149418)
		(width 0.0889)
		(layer "B.Cu")
		(net "FM_PEHPCPU1_ALERT_N")
	)
	(arc
		(start 110.417864 -231.39019)
		(mid 110.212792 -231.186511)
		(end 110.135162 -230.908098)
		(width 0.0889)
		(layer "B.Cu")
		(net "FM_PEHPCPU1_ALERT_N")
	)
	(arc
		(start 109.47781 -229.762304)
		(mid 109.290612 -229.712161)
		(end 109.103414 -229.762304)
		(width 0.0889)
		(layer "B.Cu")
		(net "FM_PEHPCPU1_ALERT_N")
	)
	(arc
		(start 108.062268 -228.944932)
		(mid 107.859681 -228.738581)
		(end 107.785662 -228.45903)
		(width 0.0889)
		(layer "B.Cu")
		(net "FM_PEHPCPU1_ALERT_N")
	)
	(arc
		(start 110.881668 -232.20045)
		(mid 110.679081 -231.994099)
		(end 110.605062 -231.714548)
		(width 0.0889)
		(layer "B.Cu")
		(net "FM_PEHPCPU1_ALERT_N")
	)
	(arc
		(start 106.845862 -225.203258)
		(mid 106.798183 -225.020358)
		(end 106.6673 -224.88398)
		(width 0.0889)
		(layer "B.Cu")
		(net "FM_PEHPCPU1_ALERT_N")
	)
	(arc
		(start 89.272364 -220.809566)
		(mid 89.085166 -220.759423)
		(end 88.897968 -220.809566)
		(width 0.0889)
		(layer "B.Cu")
		(net "FM_PEHPCPU1_ALERT_N")
	)
	(arc
		(start 93.219016 -221.133924)
		(mid 93.171337 -220.951024)
		(end 93.040454 -220.814646)
		(width 0.0889)
		(layer "B.Cu")
		(net "FM_PEHPCPU1_ALERT_N")
	)
	(arc
		(start 100.166678 -220.814646)
		(mid 100.035764 -220.951006)
		(end 99.988116 -221.133924)
		(width 0.0889)
		(layer "B.Cu")
		(net "FM_PEHPCPU1_ALERT_N")
	)
	(arc
		(start 99.14001 -221.623382)
		(mid 98.937187 -221.423151)
		(end 98.857816 -221.149418)
		(width 0.0889)
		(layer "B.Cu")
		(net "FM_PEHPCPU1_ALERT_N")
	)
	(arc
		(start 102.046278 -220.814646)
		(mid 101.915364 -220.951006)
		(end 101.867716 -221.133924)
		(width 0.0889)
		(layer "B.Cu")
		(net "FM_PEHPCPU1_ALERT_N")
	)
	(arc
		(start 103.449882 -221.632018)
		(mid 103.173407 -221.699338)
		(end 102.89921 -221.623382)
		(width 0.0889)
		(layer "B.Cu")
		(net "FM_PEHPCPU1_ALERT_N")
	)
	(arc
		(start 107.316016 -227.629466)
		(mid 107.395386 -227.355732)
		(end 107.59821 -227.155502)
		(width 0.0889)
		(layer "B.Cu")
		(net "FM_PEHPCPU1_ALERT_N")
	)
	(arc
		(start 109.947456 -230.57612)
		(mid 109.744633 -230.375889)
		(end 109.665262 -230.102156)
		(width 0.0889)
		(layer "B.Cu")
		(net "FM_PEHPCPU1_ALERT_N")
	)
	(arc
		(start 104.874568 -222.437198)
		(mid 104.600369 -222.513033)
		(end 104.323896 -222.445834)
		(width 0.0889)
		(layer "B.Cu")
		(net "FM_PEHPCPU1_ALERT_N")
	)
	(arc
		(start 94.051882 -221.632018)
		(mid 93.775407 -221.699338)
		(end 93.50121 -221.623382)
		(width 0.0889)
		(layer "B.Cu")
		(net "FM_PEHPCPU1_ALERT_N")
	)
	(arc
		(start 94.349316 -221.133924)
		(mid 94.275325 -221.41349)
		(end 94.07271 -221.619826)
		(width 0.0889)
		(layer "B.Cu")
		(net "FM_PEHPCPU1_ALERT_N")
	)
	(arc
		(start 110.135162 -230.900478)
		(mid 110.089158 -230.720541)
		(end 109.962442 -230.584756)
		(width 0.0889)
		(layer "B.Cu")
		(net "FM_PEHPCPU1_ALERT_N")
	)
	(arc
		(start 98.857816 -221.133924)
		(mid 98.810137 -220.951024)
		(end 98.679254 -220.814646)
		(width 0.0889)
		(layer "B.Cu")
		(net "FM_PEHPCPU1_ALERT_N")
	)
	(arc
		(start 111.075216 -232.528364)
		(mid 111.027537 -232.345464)
		(end 110.896654 -232.209086)
		(width 0.0889)
		(layer "B.Cu")
		(net "FM_PEHPCPU1_ALERT_N")
	)
	(arc
		(start 101.01961 -221.623382)
		(mid 100.816787 -221.423151)
		(end 100.737416 -221.149418)
		(width 0.0889)
		(layer "B.Cu")
		(net "FM_PEHPCPU1_ALERT_N")
	)
	(arc
		(start 93.50121 -221.623382)
		(mid 93.298387 -221.423151)
		(end 93.219016 -221.149418)
		(width 0.0889)
		(layer "B.Cu")
		(net "FM_PEHPCPU1_ALERT_N")
	)
	(arc
		(start 90.590116 -221.133924)
		(mid 90.516125 -221.41349)
		(end 90.31351 -221.619826)
		(width 0.0889)
		(layer "B.Cu")
		(net "FM_PEHPCPU1_ALERT_N")
	)
	(arc
		(start 107.785662 -228.45903)
		(mid 107.737983 -228.27613)
		(end 107.6071 -228.139752)
		(width 0.0889)
		(layer "B.Cu")
		(net "FM_PEHPCPU1_ALERT_N")
	)
	(arc
		(start 91.339416 -221.133924)
		(mid 91.291737 -220.951024)
		(end 91.160854 -220.814646)
		(width 0.0889)
		(layer "B.Cu")
		(net "FM_PEHPCPU1_ALERT_N")
	)
	(arc
		(start 105.71861 -223.251268)
		(mid 105.517328 -223.053781)
		(end 105.436416 -222.783654)
		(width 0.0889)
		(layer "B.Cu")
		(net "FM_PEHPCPU1_ALERT_N")
	)
	(arc
		(start 95.931482 -221.632018)
		(mid 95.655007 -221.699338)
		(end 95.38081 -221.623382)
		(width 0.0889)
		(layer "B.Cu")
		(net "FM_PEHPCPU1_ALERT_N")
	)
	(arc
		(start 99.690682 -221.632018)
		(mid 99.414207 -221.699338)
		(end 99.14001 -221.623382)
		(width 0.0889)
		(layer "B.Cu")
		(net "FM_PEHPCPU1_ALERT_N")
	)
	(arc
		(start 96.407478 -220.814646)
		(mid 96.276564 -220.951006)
		(end 96.228916 -221.133924)
		(width 0.0889)
		(layer "B.Cu")
		(net "FM_PEHPCPU1_ALERT_N")
	)
	(arc
		(start 94.911164 -220.809566)
		(mid 94.723966 -220.759423)
		(end 94.536768 -220.809566)
		(width 0.0889)
		(layer "B.Cu")
		(net "FM_PEHPCPU1_ALERT_N")
	)
	(arc
		(start 106.376216 -224.389442)
		(mid 106.328537 -224.206542)
		(end 106.197654 -224.070164)
		(width 0.0889)
		(layer "B.Cu")
		(net "FM_PEHPCPU1_ALERT_N")
	)
	(arc
		(start 97.26041 -221.623382)
		(mid 97.057587 -221.423151)
		(end 96.978216 -221.149418)
		(width 0.0889)
		(layer "B.Cu")
		(net "FM_PEHPCPU1_ALERT_N")
	)
	(arc
		(start 107.128564 -225.69297)
		(mid 106.925083 -225.492166)
		(end 106.845862 -225.217482)
		(width 0.0889)
		(layer "B.Cu")
		(net "FM_PEHPCPU1_ALERT_N")
	)
	(arc
		(start 108.53801 -229.762304)
		(mid 108.335187 -229.562073)
		(end 108.255816 -229.28834)
		(width 0.0889)
		(layer "B.Cu")
		(net "FM_PEHPCPU1_ALERT_N")
	)
	(arc
		(start 105.248964 -222.437198)
		(mid 105.061766 -222.387055)
		(end 104.874568 -222.437198)
		(width 0.0889)
		(layer "B.Cu")
		(net "FM_PEHPCPU1_ALERT_N")
	)
	(arc
		(start 97.811082 -221.632018)
		(mid 97.534607 -221.699338)
		(end 97.26041 -221.623382)
		(width 0.0889)
		(layer "B.Cu")
		(net "FM_PEHPCPU1_ALERT_N")
	)
	(arc
		(start 96.790764 -220.809566)
		(mid 96.603566 -220.759423)
		(end 96.416368 -220.809566)
		(width 0.0889)
		(layer "B.Cu")
		(net "FM_PEHPCPU1_ALERT_N")
	)
	(arc
		(start 107.6071 -227.150422)
		(mid 107.785697 -226.831144)
		(end 107.6071 -226.511866)
		(width 0.0889)
		(layer "B.Cu")
		(net "FM_PEHPCPU1_ALERT_N")
	)
	(arc
		(start 96.228916 -221.133924)
		(mid 96.154925 -221.41349)
		(end 95.95231 -221.619826)
		(width 0.0889)
		(layer "B.Cu")
		(net "FM_PEHPCPU1_ALERT_N")
	)
	(arc
		(start 88.332564 -220.809566)
		(mid 88.271201 -220.768432)
		(end 88.215724 -220.71965)
		(width 0.0889)
		(layer "B.Cu")
		(net "FM_PEHPCPU1_ALERT_N")
	)
	(arc
		(start 111.544862 -233.34218)
		(mid 111.497183 -233.15928)
		(end 111.3663 -233.022902)
		(width 0.0889)
		(layer "B.Cu")
		(net "FM_PEHPCPU1_ALERT_N")
	)
	(arc
		(start 109.665262 -230.086662)
		(mid 109.617583 -229.903762)
		(end 109.4867 -229.767384)
		(width 0.0889)
		(layer "B.Cu")
		(net "FM_PEHPCPU1_ALERT_N")
	)
	(arc
		(start 111.7727 -233.796078)
		(mid 111.608085 -233.602514)
		(end 111.544862 -233.356404)
		(width 0.0889)
		(layer "B.Cu")
		(net "FM_PEHPCPU1_ALERT_N")
	)
	(arc
		(start 110.605062 -231.705912)
		(mid 110.552792 -231.523547)
		(end 110.417864 -231.39019)
		(width 0.0889)
		(layer "B.Cu")
		(net "FM_PEHPCPU1_ALERT_N")
	)
	(arc
		(start 95.098616 -221.133924)
		(mid 95.050937 -220.951024)
		(end 94.920054 -220.814646)
		(width 0.0889)
		(layer "B.Cu")
		(net "FM_PEHPCPU1_ALERT_N")
	)
	(arc
		(start 91.151964 -220.809566)
		(mid 90.964766 -220.759423)
		(end 90.777568 -220.809566)
		(width 0.0889)
		(layer "B.Cu")
		(net "FM_PEHPCPU1_ALERT_N")
	)
	(arc
		(start 104.026462 -221.94774)
		(mid 103.978783 -221.76484)
		(end 103.8479 -221.628462)
		(width 0.0889)
		(layer "B.Cu")
		(net "FM_PEHPCPU1_ALERT_N")
	)
	(segment
		(start 359.580434 -234.691936)
		(end 359.580434 -234.15625)
		(width 0.12954)
		(layer "F.Cu")
		(net "FM_PEHPCPU0_ALERT_N")
	)
	(segment
		(start 359.58018 -234.69219)
		(end 359.580434 -234.691936)
		(width 0.12954)
		(layer "F.Cu")
		(net "FM_PEHPCPU0_ALERT_N")
	)
	(via
		(at 359.580434 -234.15625)
		(size 0.4572)
		(drill 0.2032)
		(layers "F.Cu" "B.Cu")
		(net "FM_PEHPCPU0_ALERT_N")
	)
	(via
		(at 372.767098 -195.74891)
		(size 0.6604)
		(drill 0.3302)
		(layers "F.Cu" "B.Cu")
		(net "FM_PEHPCPU0_ALERT_N")
	)
	(segment
		(start 364.567978 -224.875344)
		(end 364.561882 -224.8789)
		(width 0.0889)
		(layer "B.Cu")
		(net "FM_PEHPCPU0_ALERT_N")
	)
	(segment
		(start 387.341364 -223.02724)
		(end 387.117336 -223.251268)
		(width 0.0889)
		(layer "B.Cu")
		(net "FM_PEHPCPU0_ALERT_N")
	)
	(segment
		(start 364.37443 -225.203258)
		(end 364.37443 -225.225356)
		(width 0.0889)
		(layer "B.Cu")
		(net "FM_PEHPCPU0_ALERT_N")
	)
	(segment
		(start 362.964984 -229.272846)
		(end 362.964984 -229.282752)
		(width 0.0889)
		(layer "B.Cu")
		(net "FM_PEHPCPU0_ALERT_N")
	)
	(segment
		(start 373.336058 -224.07753)
		(end 373.076978 -224.07753)
		(width 0.0889)
		(layer "B.Cu")
		(net "FM_PEHPCPU0_ALERT_N")
	)
	(segment
		(start 364.44809 -185.960766)
		(end 365.68761 -184.721246)
		(width 0.12954)
		(layer "B.Cu")
		(net "FM_PEHPCPU0_ALERT_N")
	)
	(segment
		(start 380.538736 -223.251268)
		(end 380.528322 -223.257364)
		(width 0.0889)
		(layer "B.Cu")
		(net "FM_PEHPCPU0_ALERT_N")
	)
	(segment
		(start 374.20042 -223.11741)
		(end 373.922798 -223.11741)
		(width 0.0889)
		(layer "B.Cu")
		(net "FM_PEHPCPU0_ALERT_N")
	)
	(segment
		(start 360.808778 -233.014266)
		(end 360.802682 -233.017822)
		(width 0.0889)
		(layer "B.Cu")
		(net "FM_PEHPCPU0_ALERT_N")
	)
	(segment
		(start 364.812834 -186.367674)
		(end 364.812834 -190.459106)
		(width 0.12954)
		(layer "B.Cu")
		(net "FM_PEHPCPU0_ALERT_N")
	)
	(segment
		(start 371.921278 -224.83445)
		(end 371.575838 -224.83445)
		(width 0.0889)
		(layer "B.Cu")
		(net "FM_PEHPCPU0_ALERT_N")
	)
	(segment
		(start 370.112798 -224.88017)
		(end 369.708938 -224.88017)
		(width 0.0889)
		(layer "B.Cu")
		(net "FM_PEHPCPU0_ALERT_N")
	)
	(segment
		(start 364.561882 -224.8789)
		(end 364.552992 -224.88398)
		(width 0.0889)
		(layer "B.Cu")
		(net "FM_PEHPCPU0_ALERT_N")
	)
	(segment
		(start 362.682536 -229.762304)
		(end 362.673646 -229.767384)
		(width 0.0889)
		(layer "B.Cu")
		(net "FM_PEHPCPU0_ALERT_N")
	)
	(segment
		(start 372.261638 -224.49409)
		(end 371.921278 -224.83445)
		(width 0.0889)
		(layer "B.Cu")
		(net "FM_PEHPCPU0_ALERT_N")
	)
	(segment
		(start 387.267196 -202.158854)
		(end 387.267196 -215.998298)
		(width 0.12954)
		(layer "B.Cu")
		(net "FM_PEHPCPU0_ALERT_N")
	)
	(segment
		(start 373.076978 -224.07753)
		(end 372.944898 -223.94545)
		(width 0.0889)
		(layer "B.Cu")
		(net "FM_PEHPCPU0_ALERT_N")
	)
	(segment
		(start 378.903738 -195.74891)
		(end 382.617218 -199.46239)
		(width 0.12954)
		(layer "B.Cu")
		(net "FM_PEHPCPU0_ALERT_N")
	)
	(segment
		(start 367.524538 -224.60077)
		(end 367.524538 -224.17659)
		(width 0.0889)
		(layer "B.Cu")
		(net "FM_PEHPCPU0_ALERT_N")
	)
	(segment
		(start 362.21289 -230.57612)
		(end 362.204 -230.5812)
		(width 0.0889)
		(layer "B.Cu")
		(net "FM_PEHPCPU0_ALERT_N")
	)
	(segment
		(start 366.963198 -223.88957)
		(end 366.676178 -224.17659)
		(width 0.0889)
		(layer "B.Cu")
		(net "FM_PEHPCPU0_ALERT_N")
	)
	(segment
		(start 370.755418 -223.85147)
		(end 370.442998 -224.16389)
		(width 0.0889)
		(layer "B.Cu")
		(net "FM_PEHPCPU0_ALERT_N")
	)
	(segment
		(start 368.774218 -223.90735)
		(end 368.525298 -224.15627)
		(width 0.0889)
		(layer "B.Cu")
		(net "FM_PEHPCPU0_ALERT_N")
	)
	(segment
		(start 359.736898 -233.885232)
		(end 359.580434 -234.15625)
		(width 0.0889)
		(layer "B.Cu")
		(net "FM_PEHPCPU0_ALERT_N")
	)
	(segment
		(start 373.734838 -223.67875)
		(end 373.336058 -224.07753)
		(width 0.0889)
		(layer "B.Cu")
		(net "FM_PEHPCPU0_ALERT_N")
	)
	(segment
		(start 363.152436 -228.948488)
		(end 363.143546 -228.953568)
		(width 0.0889)
		(layer "B.Cu")
		(net "FM_PEHPCPU0_ALERT_N")
	)
	(segment
		(start 386.566664 -223.259904)
		(end 386.551932 -223.251268)
		(width 0.0889)
		(layer "B.Cu")
		(net "FM_PEHPCPU0_ALERT_N")
	)
	(segment
		(start 361.278932 -232.20045)
		(end 361.272836 -232.204006)
		(width 0.0889)
		(layer "B.Cu")
		(net "FM_PEHPCPU0_ALERT_N")
	)
	(segment
		(start 364.44809 -185.981848)
		(end 364.44809 -185.960766)
		(width 0.12954)
		(layer "B.Cu")
		(net "FM_PEHPCPU0_ALERT_N")
	)
	(segment
		(start 368.525298 -224.62363)
		(end 368.243358 -224.90557)
		(width 0.0889)
		(layer "B.Cu")
		(net "FM_PEHPCPU0_ALERT_N")
	)
	(segment
		(start 364.812834 -190.459106)
		(end 370.102638 -195.74891)
		(width 0.12954)
		(layer "B.Cu")
		(net "FM_PEHPCPU0_ALERT_N")
	)
	(segment
		(start 364.44809 -185.981848)
		(end 364.44809 -186.00293)
		(width 0.12954)
		(layer "B.Cu")
		(net "FM_PEHPCPU0_ALERT_N")
	)
	(segment
		(start 370.442998 -224.54997)
		(end 370.112798 -224.88017)
		(width 0.0889)
		(layer "B.Cu")
		(net "FM_PEHPCPU0_ALERT_N")
	)
	(segment
		(start 369.048538 -223.90735)
		(end 368.774218 -223.90735)
		(width 0.0889)
		(layer "B.Cu")
		(net "FM_PEHPCPU0_ALERT_N")
	)
	(segment
		(start 371.575838 -224.83445)
		(end 371.377718 -224.63633)
		(width 0.0889)
		(layer "B.Cu")
		(net "FM_PEHPCPU0_ALERT_N")
	)
	(segment
		(start 365.517938 -223.98863)
		(end 365.11103 -223.98863)
		(width 0.0889)
		(layer "B.Cu")
		(net "FM_PEHPCPU0_ALERT_N")
	)
	(segment
		(start 365.637318 -224.55505)
		(end 365.637318 -224.10801)
		(width 0.0889)
		(layer "B.Cu")
		(net "FM_PEHPCPU0_ALERT_N")
	)
	(segment
		(start 365.11103 -223.98863)
		(end 365.038132 -224.061528)
		(width 0.0889)
		(layer "B.Cu")
		(net "FM_PEHPCPU0_ALERT_N")
	)
	(segment
		(start 366.389158 -224.85477)
		(end 365.937038 -224.85477)
		(width 0.0889)
		(layer "B.Cu")
		(net "FM_PEHPCPU0_ALERT_N")
	)
	(segment
		(start 374.899936 -223.251268)
		(end 374.889522 -223.257364)
		(width 0.0889)
		(layer "B.Cu")
		(net "FM_PEHPCPU0_ALERT_N")
	)
	(segment
		(start 363.434884 -226.831144)
		(end 363.434884 -226.84105)
		(width 0.0889)
		(layer "B.Cu")
		(net "FM_PEHPCPU0_ALERT_N")
	)
	(segment
		(start 376.779536 -223.251268)
		(end 376.769122 -223.257364)
		(width 0.0889)
		(layer "B.Cu")
		(net "FM_PEHPCPU0_ALERT_N")
	)
	(segment
		(start 365.637318 -224.10801)
		(end 365.517938 -223.98863)
		(width 0.0889)
		(layer "B.Cu")
		(net "FM_PEHPCPU0_ALERT_N")
	)
	(segment
		(start 377.719082 -223.251268)
		(end 377.708668 -223.257364)
		(width 0.0889)
		(layer "B.Cu")
		(net "FM_PEHPCPU0_ALERT_N")
	)
	(segment
		(start 369.378738 -224.23755)
		(end 369.048538 -223.90735)
		(width 0.0889)
		(layer "B.Cu")
		(net "FM_PEHPCPU0_ALERT_N")
	)
	(segment
		(start 384.570732 -199.46239)
		(end 387.267196 -202.158854)
		(width 0.12954)
		(layer "B.Cu")
		(net "FM_PEHPCPU0_ALERT_N")
	)
	(segment
		(start 361.272836 -232.204006)
		(end 361.263946 -232.209086)
		(width 0.0889)
		(layer "B.Cu")
		(net "FM_PEHPCPU0_ALERT_N")
	)
	(segment
		(start 374.334278 -223.251268)
		(end 374.20042 -223.11741)
		(width 0.0889)
		(layer "B.Cu")
		(net "FM_PEHPCPU0_ALERT_N")
	)
	(segment
		(start 372.944898 -223.94545)
		(end 372.541038 -223.94545)
		(width 0.0889)
		(layer "B.Cu")
		(net "FM_PEHPCPU0_ALERT_N")
	)
	(segment
		(start 384.682492 -223.257364)
		(end 384.672078 -223.251268)
		(width 0.0889)
		(layer "B.Cu")
		(net "FM_PEHPCPU0_ALERT_N")
	)
	(segment
		(start 363.904784 -226.017328)
		(end 363.904784 -226.027234)
		(width 0.0889)
		(layer "B.Cu")
		(net "FM_PEHPCPU0_ALERT_N")
	)
	(segment
		(start 363.622336 -226.506786)
		(end 363.613446 -226.511866)
		(width 0.0889)
		(layer "B.Cu")
		(net "FM_PEHPCPU0_ALERT_N")
	)
	(segment
		(start 368.525298 -224.15627)
		(end 368.525298 -224.62363)
		(width 0.0889)
		(layer "B.Cu")
		(net "FM_PEHPCPU0_ALERT_N")
	)
	(segment
		(start 387.341364 -216.072466)
		(end 387.341364 -223.02724)
		(width 0.12954)
		(layer "B.Cu")
		(net "FM_PEHPCPU0_ALERT_N")
	)
	(segment
		(start 382.617218 -199.46239)
		(end 384.570732 -199.46239)
		(width 0.12954)
		(layer "B.Cu")
		(net "FM_PEHPCPU0_ALERT_N")
	)
	(segment
		(start 378.659136 -223.251268)
		(end 378.648722 -223.257364)
		(width 0.0889)
		(layer "B.Cu")
		(net "FM_PEHPCPU0_ALERT_N")
	)
	(segment
		(start 372.767098 -195.74891)
		(end 378.903738 -195.74891)
		(width 0.12954)
		(layer "B.Cu")
		(net "FM_PEHPCPU0_ALERT_N")
	)
	(segment
		(start 361.74299 -231.39019)
		(end 361.7341 -231.39527)
		(width 0.0889)
		(layer "B.Cu")
		(net "FM_PEHPCPU0_ALERT_N")
	)
	(segment
		(start 372.261638 -224.22485)
		(end 372.261638 -224.49409)
		(width 0.0889)
		(layer "B.Cu")
		(net "FM_PEHPCPU0_ALERT_N")
	)
	(segment
		(start 373.922798 -223.11741)
		(end 373.734838 -223.30537)
		(width 0.0889)
		(layer "B.Cu")
		(net "FM_PEHPCPU0_ALERT_N")
	)
	(segment
		(start 384.297682 -223.251268)
		(end 384.287268 -223.257364)
		(width 0.0889)
		(layer "B.Cu")
		(net "FM_PEHPCPU0_ALERT_N")
	)
	(segment
		(start 367.237518 -223.88957)
		(end 366.963198 -223.88957)
		(width 0.0889)
		(layer "B.Cu")
		(net "FM_PEHPCPU0_ALERT_N")
	)
	(segment
		(start 372.541038 -223.94545)
		(end 372.261638 -224.22485)
		(width 0.0889)
		(layer "B.Cu")
		(net "FM_PEHPCPU0_ALERT_N")
	)
	(segment
		(start 370.102638 -195.74891)
		(end 372.767098 -195.74891)
		(width 0.12954)
		(layer "B.Cu")
		(net "FM_PEHPCPU0_ALERT_N")
	)
	(segment
		(start 363.43463 -228.458268)
		(end 363.43463 -228.474524)
		(width 0.0889)
		(layer "B.Cu")
		(net "FM_PEHPCPU0_ALERT_N")
	)
	(segment
		(start 366.676178 -224.17659)
		(end 366.676178 -224.56775)
		(width 0.0889)
		(layer "B.Cu")
		(net "FM_PEHPCPU0_ALERT_N")
	)
	(segment
		(start 370.442998 -224.16389)
		(end 370.442998 -224.54997)
		(width 0.0889)
		(layer "B.Cu")
		(net "FM_PEHPCPU0_ALERT_N")
	)
	(segment
		(start 375.839482 -223.251268)
		(end 375.829068 -223.257364)
		(width 0.0889)
		(layer "B.Cu")
		(net "FM_PEHPCPU0_ALERT_N")
	)
	(segment
		(start 368.243358 -224.90557)
		(end 367.829338 -224.90557)
		(width 0.0889)
		(layer "B.Cu")
		(net "FM_PEHPCPU0_ALERT_N")
	)
	(segment
		(start 387.267196 -215.998298)
		(end 387.341364 -216.072466)
		(width 0.12954)
		(layer "B.Cu")
		(net "FM_PEHPCPU0_ALERT_N")
	)
	(segment
		(start 365.032036 -224.065084)
		(end 365.023146 -224.070164)
		(width 0.0889)
		(layer "B.Cu")
		(net "FM_PEHPCPU0_ALERT_N")
	)
	(segment
		(start 365.937038 -224.85477)
		(end 365.637318 -224.55505)
		(width 0.0889)
		(layer "B.Cu")
		(net "FM_PEHPCPU0_ALERT_N")
	)
	(segment
		(start 371.377718 -224.63633)
		(end 371.377718 -224.27565)
		(width 0.0889)
		(layer "B.Cu")
		(net "FM_PEHPCPU0_ALERT_N")
	)
	(segment
		(start 369.378738 -224.54997)
		(end 369.378738 -224.23755)
		(width 0.0889)
		(layer "B.Cu")
		(net "FM_PEHPCPU0_ALERT_N")
	)
	(segment
		(start 371.377718 -224.27565)
		(end 370.953538 -223.85147)
		(width 0.0889)
		(layer "B.Cu")
		(net "FM_PEHPCPU0_ALERT_N")
	)
	(segment
		(start 364.092236 -225.69297)
		(end 364.083346 -225.69805)
		(width 0.0889)
		(layer "B.Cu")
		(net "FM_PEHPCPU0_ALERT_N")
	)
	(segment
		(start 373.734838 -223.30537)
		(end 373.734838 -223.67875)
		(width 0.0889)
		(layer "B.Cu")
		(net "FM_PEHPCPU0_ALERT_N")
	)
	(segment
		(start 367.829338 -224.90557)
		(end 367.524538 -224.60077)
		(width 0.0889)
		(layer "B.Cu")
		(net "FM_PEHPCPU0_ALERT_N")
	)
	(segment
		(start 359.825798 -233.86161)
		(end 359.736898 -233.885232)
		(width 0.0889)
		(layer "B.Cu")
		(net "FM_PEHPCPU0_ALERT_N")
	)
	(segment
		(start 365.038132 -224.061528)
		(end 365.032036 -224.065084)
		(width 0.0889)
		(layer "B.Cu")
		(net "FM_PEHPCPU0_ALERT_N")
	)
	(segment
		(start 364.44809 -186.00293)
		(end 364.812834 -186.367674)
		(width 0.12954)
		(layer "B.Cu")
		(net "FM_PEHPCPU0_ALERT_N")
	)
	(segment
		(start 362.495084 -230.086662)
		(end 362.495084 -230.102156)
		(width 0.0889)
		(layer "B.Cu")
		(net "FM_PEHPCPU0_ALERT_N")
	)
	(segment
		(start 367.524538 -224.17659)
		(end 367.237518 -223.88957)
		(width 0.0889)
		(layer "B.Cu")
		(net "FM_PEHPCPU0_ALERT_N")
	)
	(segment
		(start 362.025438 -230.900478)
		(end 362.025438 -230.914702)
		(width 0.0889)
		(layer "B.Cu")
		(net "FM_PEHPCPU0_ALERT_N")
	)
	(segment
		(start 369.708938 -224.88017)
		(end 369.378738 -224.54997)
		(width 0.0889)
		(layer "B.Cu")
		(net "FM_PEHPCPU0_ALERT_N")
	)
	(segment
		(start 366.676178 -224.56775)
		(end 366.389158 -224.85477)
		(width 0.0889)
		(layer "B.Cu")
		(net "FM_PEHPCPU0_ALERT_N")
	)
	(segment
		(start 360.802682 -233.017822)
		(end 360.793792 -233.022902)
		(width 0.0889)
		(layer "B.Cu")
		(net "FM_PEHPCPU0_ALERT_N")
	)
	(segment
		(start 365.68761 -184.721246)
		(end 365.68761 -184.051448)
		(width 0.12954)
		(layer "B.Cu")
		(net "FM_PEHPCPU0_ALERT_N")
	)
	(segment
		(start 360.61523 -233.34218)
		(end 360.61523 -233.364278)
		(width 0.0889)
		(layer "B.Cu")
		(net "FM_PEHPCPU0_ALERT_N")
	)
	(segment
		(start 379.598682 -223.251268)
		(end 379.588268 -223.257364)
		(width 0.0889)
		(layer "B.Cu")
		(net "FM_PEHPCPU0_ALERT_N")
	)
	(segment
		(start 370.953538 -223.85147)
		(end 370.755418 -223.85147)
		(width 0.0889)
		(layer "B.Cu")
		(net "FM_PEHPCPU0_ALERT_N")
	)
	(arc
		(start 364.37443 -225.225356)
		(mid 364.293519 -225.495484)
		(end 364.092236 -225.69297)
		(width 0.0889)
		(layer "B.Cu")
		(net "FM_PEHPCPU0_ALERT_N")
	)
	(arc
		(start 385.612132 -223.251268)
		(mid 385.424934 -223.201125)
		(end 385.237736 -223.251268)
		(width 0.0889)
		(layer "B.Cu")
		(net "FM_PEHPCPU0_ALERT_N")
	)
	(arc
		(start 362.495084 -230.102156)
		(mid 362.415714 -230.37589)
		(end 362.21289 -230.57612)
		(width 0.0889)
		(layer "B.Cu")
		(net "FM_PEHPCPU0_ALERT_N")
	)
	(arc
		(start 362.673646 -229.767384)
		(mid 362.542732 -229.903744)
		(end 362.495084 -230.086662)
		(width 0.0889)
		(layer "B.Cu")
		(net "FM_PEHPCPU0_ALERT_N")
	)
	(arc
		(start 361.555538 -231.714548)
		(mid 361.481547 -231.994114)
		(end 361.278932 -232.20045)
		(width 0.0889)
		(layer "B.Cu")
		(net "FM_PEHPCPU0_ALERT_N")
	)
	(arc
		(start 360.61523 -233.364278)
		(mid 360.534319 -233.634406)
		(end 360.333036 -233.831892)
		(width 0.0889)
		(layer "B.Cu")
		(net "FM_PEHPCPU0_ALERT_N")
	)
	(arc
		(start 385.237736 -223.251268)
		(mid 384.960923 -223.327104)
		(end 384.682492 -223.257364)
		(width 0.0889)
		(layer "B.Cu")
		(net "FM_PEHPCPU0_ALERT_N")
	)
	(arc
		(start 386.551932 -223.251268)
		(mid 386.364734 -223.201125)
		(end 386.177536 -223.251268)
		(width 0.0889)
		(layer "B.Cu")
		(net "FM_PEHPCPU0_ALERT_N")
	)
	(arc
		(start 365.023146 -224.070164)
		(mid 364.892232 -224.206524)
		(end 364.844584 -224.389442)
		(width 0.0889)
		(layer "B.Cu")
		(net "FM_PEHPCPU0_ALERT_N")
	)
	(arc
		(start 363.143546 -228.953568)
		(mid 363.012632 -229.089928)
		(end 362.964984 -229.272846)
		(width 0.0889)
		(layer "B.Cu")
		(net "FM_PEHPCPU0_ALERT_N")
	)
	(arc
		(start 375.274332 -223.251268)
		(mid 375.087134 -223.201125)
		(end 374.899936 -223.251268)
		(width 0.0889)
		(layer "B.Cu")
		(net "FM_PEHPCPU0_ALERT_N")
	)
	(arc
		(start 377.708668 -223.257364)
		(mid 377.43049 -223.327056)
		(end 377.153932 -223.251268)
		(width 0.0889)
		(layer "B.Cu")
		(net "FM_PEHPCPU0_ALERT_N")
	)
	(arc
		(start 377.153932 -223.251268)
		(mid 376.966734 -223.201125)
		(end 376.779536 -223.251268)
		(width 0.0889)
		(layer "B.Cu")
		(net "FM_PEHPCPU0_ALERT_N")
	)
	(arc
		(start 364.844584 -224.389442)
		(mid 364.770593 -224.669008)
		(end 364.567978 -224.875344)
		(width 0.0889)
		(layer "B.Cu")
		(net "FM_PEHPCPU0_ALERT_N")
	)
	(arc
		(start 363.43463 -228.474524)
		(mid 363.35526 -228.748258)
		(end 363.152436 -228.948488)
		(width 0.0889)
		(layer "B.Cu")
		(net "FM_PEHPCPU0_ALERT_N")
	)
	(arc
		(start 362.204 -230.5812)
		(mid 362.073086 -230.71756)
		(end 362.025438 -230.900478)
		(width 0.0889)
		(layer "B.Cu")
		(net "FM_PEHPCPU0_ALERT_N")
	)
	(arc
		(start 383.358136 -223.251268)
		(mid 383.075434 -223.32701)
		(end 382.792732 -223.251268)
		(width 0.0889)
		(layer "B.Cu")
		(net "FM_PEHPCPU0_ALERT_N")
	)
	(arc
		(start 381.478536 -223.251268)
		(mid 381.195834 -223.32701)
		(end 380.913132 -223.251268)
		(width 0.0889)
		(layer "B.Cu")
		(net "FM_PEHPCPU0_ALERT_N")
	)
	(arc
		(start 360.793792 -233.022902)
		(mid 360.662878 -233.159262)
		(end 360.61523 -233.34218)
		(width 0.0889)
		(layer "B.Cu")
		(net "FM_PEHPCPU0_ALERT_N")
	)
	(arc
		(start 363.434884 -226.84105)
		(mid 363.356773 -227.117999)
		(end 363.152436 -227.320602)
		(width 0.0889)
		(layer "B.Cu")
		(net "FM_PEHPCPU0_ALERT_N")
	)
	(arc
		(start 376.213878 -223.251268)
		(mid 376.02668 -223.201125)
		(end 375.839482 -223.251268)
		(width 0.0889)
		(layer "B.Cu")
		(net "FM_PEHPCPU0_ALERT_N")
	)
	(arc
		(start 383.732532 -223.251268)
		(mid 383.545334 -223.201125)
		(end 383.358136 -223.251268)
		(width 0.0889)
		(layer "B.Cu")
		(net "FM_PEHPCPU0_ALERT_N")
	)
	(arc
		(start 363.613446 -226.511866)
		(mid 363.482532 -226.648226)
		(end 363.434884 -226.831144)
		(width 0.0889)
		(layer "B.Cu")
		(net "FM_PEHPCPU0_ALERT_N")
	)
	(arc
		(start 386.177536 -223.251268)
		(mid 385.894834 -223.32701)
		(end 385.612132 -223.251268)
		(width 0.0889)
		(layer "B.Cu")
		(net "FM_PEHPCPU0_ALERT_N")
	)
	(arc
		(start 387.117336 -223.251268)
		(mid 386.843107 -223.327193)
		(end 386.566664 -223.259904)
		(width 0.0889)
		(layer "B.Cu")
		(net "FM_PEHPCPU0_ALERT_N")
	)
	(arc
		(start 380.913132 -223.251268)
		(mid 380.725934 -223.201125)
		(end 380.538736 -223.251268)
		(width 0.0889)
		(layer "B.Cu")
		(net "FM_PEHPCPU0_ALERT_N")
	)
	(arc
		(start 374.889522 -223.257364)
		(mid 374.61109 -223.327178)
		(end 374.334278 -223.251268)
		(width 0.0889)
		(layer "B.Cu")
		(net "FM_PEHPCPU0_ALERT_N")
	)
	(arc
		(start 363.152436 -227.320602)
		(mid 362.96526 -227.64496)
		(end 363.152436 -227.969318)
		(width 0.0889)
		(layer "B.Cu")
		(net "FM_PEHPCPU0_ALERT_N")
	)
	(arc
		(start 376.769122 -223.257364)
		(mid 376.49069 -223.327178)
		(end 376.213878 -223.251268)
		(width 0.0889)
		(layer "B.Cu")
		(net "FM_PEHPCPU0_ALERT_N")
	)
	(arc
		(start 361.085384 -232.528364)
		(mid 361.011393 -232.80793)
		(end 360.808778 -233.014266)
		(width 0.0889)
		(layer "B.Cu")
		(net "FM_PEHPCPU0_ALERT_N")
	)
	(arc
		(start 375.829068 -223.257364)
		(mid 375.55089 -223.327056)
		(end 375.274332 -223.251268)
		(width 0.0889)
		(layer "B.Cu")
		(net "FM_PEHPCPU0_ALERT_N")
	)
	(arc
		(start 361.7341 -231.39527)
		(mid 361.603186 -231.53163)
		(end 361.555538 -231.714548)
		(width 0.0889)
		(layer "B.Cu")
		(net "FM_PEHPCPU0_ALERT_N")
	)
	(arc
		(start 360.333036 -233.831892)
		(mid 360.082939 -233.906918)
		(end 359.825798 -233.86161)
		(width 0.0889)
		(layer "B.Cu")
		(net "FM_PEHPCPU0_ALERT_N")
	)
	(arc
		(start 378.648722 -223.257364)
		(mid 378.37029 -223.327178)
		(end 378.093478 -223.251268)
		(width 0.0889)
		(layer "B.Cu")
		(net "FM_PEHPCPU0_ALERT_N")
	)
	(arc
		(start 384.287268 -223.257364)
		(mid 384.00909 -223.327056)
		(end 383.732532 -223.251268)
		(width 0.0889)
		(layer "B.Cu")
		(net "FM_PEHPCPU0_ALERT_N")
	)
	(arc
		(start 379.973078 -223.251268)
		(mid 379.78588 -223.201125)
		(end 379.598682 -223.251268)
		(width 0.0889)
		(layer "B.Cu")
		(net "FM_PEHPCPU0_ALERT_N")
	)
	(arc
		(start 381.852932 -223.251268)
		(mid 381.665734 -223.201125)
		(end 381.478536 -223.251268)
		(width 0.0889)
		(layer "B.Cu")
		(net "FM_PEHPCPU0_ALERT_N")
	)
	(arc
		(start 362.025438 -230.914702)
		(mid 361.946297 -231.189325)
		(end 361.74299 -231.39019)
		(width 0.0889)
		(layer "B.Cu")
		(net "FM_PEHPCPU0_ALERT_N")
	)
	(arc
		(start 380.528322 -223.257364)
		(mid 380.24989 -223.327178)
		(end 379.973078 -223.251268)
		(width 0.0889)
		(layer "B.Cu")
		(net "FM_PEHPCPU0_ALERT_N")
	)
	(arc
		(start 364.083346 -225.69805)
		(mid 363.952432 -225.83441)
		(end 363.904784 -226.017328)
		(width 0.0889)
		(layer "B.Cu")
		(net "FM_PEHPCPU0_ALERT_N")
	)
	(arc
		(start 378.093478 -223.251268)
		(mid 377.90628 -223.201125)
		(end 377.719082 -223.251268)
		(width 0.0889)
		(layer "B.Cu")
		(net "FM_PEHPCPU0_ALERT_N")
	)
	(arc
		(start 363.152436 -227.969318)
		(mid 363.359037 -228.175992)
		(end 363.43463 -228.458268)
		(width 0.0889)
		(layer "B.Cu")
		(net "FM_PEHPCPU0_ALERT_N")
	)
	(arc
		(start 382.418336 -223.251268)
		(mid 382.135634 -223.32701)
		(end 381.852932 -223.251268)
		(width 0.0889)
		(layer "B.Cu")
		(net "FM_PEHPCPU0_ALERT_N")
	)
	(arc
		(start 362.964984 -229.282752)
		(mid 362.886873 -229.559701)
		(end 362.682536 -229.762304)
		(width 0.0889)
		(layer "B.Cu")
		(net "FM_PEHPCPU0_ALERT_N")
	)
	(arc
		(start 364.552992 -224.88398)
		(mid 364.422078 -225.02034)
		(end 364.37443 -225.203258)
		(width 0.0889)
		(layer "B.Cu")
		(net "FM_PEHPCPU0_ALERT_N")
	)
	(arc
		(start 363.904784 -226.027234)
		(mid 363.826673 -226.304183)
		(end 363.622336 -226.506786)
		(width 0.0889)
		(layer "B.Cu")
		(net "FM_PEHPCPU0_ALERT_N")
	)
	(arc
		(start 382.792732 -223.251268)
		(mid 382.605534 -223.201125)
		(end 382.418336 -223.251268)
		(width 0.0889)
		(layer "B.Cu")
		(net "FM_PEHPCPU0_ALERT_N")
	)
	(arc
		(start 379.033532 -223.251268)
		(mid 378.846334 -223.201125)
		(end 378.659136 -223.251268)
		(width 0.0889)
		(layer "B.Cu")
		(net "FM_PEHPCPU0_ALERT_N")
	)
	(arc
		(start 379.588268 -223.257364)
		(mid 379.31009 -223.327056)
		(end 379.033532 -223.251268)
		(width 0.0889)
		(layer "B.Cu")
		(net "FM_PEHPCPU0_ALERT_N")
	)
	(arc
		(start 361.263946 -232.209086)
		(mid 361.133032 -232.345446)
		(end 361.085384 -232.528364)
		(width 0.0889)
		(layer "B.Cu")
		(net "FM_PEHPCPU0_ALERT_N")
	)
	(arc
		(start 384.672078 -223.251268)
		(mid 384.48488 -223.201125)
		(end 384.297682 -223.251268)
		(width 0.0889)
		(layer "B.Cu")
		(net "FM_PEHPCPU0_ALERT_N")
	)
	(segment
		(start 169.58564 -108.975398)
		(end 170.155616 -108.975398)
		(width 0.12954)
		(layer "F.Cu")
		(net "FM_PECI_MUX_SEL_N")
	)
	(segment
		(start 289.856164 -59.843924)
		(end 296.914316 -59.843924)
		(width 0.12954)
		(layer "F.Cu")
		(net "FM_PECI_MUX_SEL_N")
	)
	(segment
		(start 284.52826 -64.935608)
		(end 284.76448 -64.935608)
		(width 0.12954)
		(layer "F.Cu")
		(net "FM_PECI_MUX_SEL_N")
	)
	(segment
		(start 284.76448 -64.935608)
		(end 289.856164 -59.843924)
		(width 0.12954)
		(layer "F.Cu")
		(net "FM_PECI_MUX_SEL_N")
	)
	(segment
		(start 296.914316 -59.843924)
		(end 299.22216 -62.151768)
		(width 0.12954)
		(layer "F.Cu")
		(net "FM_PECI_MUX_SEL_N")
	)
	(segment
		(start 299.22216 -62.151768)
		(end 304.1396 -62.151768)
		(width 0.12954)
		(layer "F.Cu")
		(net "FM_PECI_MUX_SEL_N")
	)
	(via
		(at 169.58564 -108.975398)
		(size 0.4572)
		(drill 0.254)
		(layers "F.Cu" "B.Cu")
		(net "FM_PECI_MUX_SEL_N")
	)
	(via
		(at 284.52826 -64.935608)
		(size 0.508)
		(drill 0.254)
		(layers "F.Cu" "B.Cu")
		(net "FM_PECI_MUX_SEL_N")
	)
	(segment
		(start 168.88968 -108.279438)
		(end 168.88968 -99.908868)
		(width 0.127)
		(layer "In13.Cu")
		(net "FM_PECI_MUX_SEL_N")
	)
	(segment
		(start 169.41546 -99.383088)
		(end 169.41546 -91.306142)
		(width 0.127)
		(layer "In13.Cu")
		(net "FM_PECI_MUX_SEL_N")
	)
	(segment
		(start 181.474618 -84.376768)
		(end 219.273882 -84.376768)
		(width 0.127)
		(layer "In13.Cu")
		(net "FM_PECI_MUX_SEL_N")
	)
	(segment
		(start 168.88968 -99.908868)
		(end 169.41546 -99.383088)
		(width 0.127)
		(layer "In13.Cu")
		(net "FM_PECI_MUX_SEL_N")
	)
	(segment
		(start 176.034192 -89.817194)
		(end 181.474618 -84.376768)
		(width 0.127)
		(layer "In13.Cu")
		(net "FM_PECI_MUX_SEL_N")
	)
	(segment
		(start 169.58564 -108.975398)
		(end 168.88968 -108.279438)
		(width 0.127)
		(layer "In13.Cu")
		(net "FM_PECI_MUX_SEL_N")
	)
	(segment
		(start 243.904516 -82.25155)
		(end 276.816312 -82.25155)
		(width 0.127)
		(layer "In13.Cu")
		(net "FM_PECI_MUX_SEL_N")
	)
	(segment
		(start 170.904408 -89.817194)
		(end 176.034192 -89.817194)
		(width 0.127)
		(layer "In13.Cu")
		(net "FM_PECI_MUX_SEL_N")
	)
	(segment
		(start 276.816312 -82.25155)
		(end 284.461966 -74.605896)
		(width 0.127)
		(layer "In13.Cu")
		(net "FM_PECI_MUX_SEL_N")
	)
	(segment
		(start 284.461966 -65.001902)
		(end 284.52826 -64.935608)
		(width 0.127)
		(layer "In13.Cu")
		(net "FM_PECI_MUX_SEL_N")
	)
	(segment
		(start 169.41546 -91.306142)
		(end 170.904408 -89.817194)
		(width 0.127)
		(layer "In13.Cu")
		(net "FM_PECI_MUX_SEL_N")
	)
	(segment
		(start 219.273882 -84.376768)
		(end 222.590868 -87.693754)
		(width 0.127)
		(layer "In13.Cu")
		(net "FM_PECI_MUX_SEL_N")
	)
	(segment
		(start 222.590868 -87.693754)
		(end 238.462312 -87.693754)
		(width 0.127)
		(layer "In13.Cu")
		(net "FM_PECI_MUX_SEL_N")
	)
	(segment
		(start 284.461966 -74.605896)
		(end 284.461966 -65.001902)
		(width 0.127)
		(layer "In13.Cu")
		(net "FM_PECI_MUX_SEL_N")
	)
	(segment
		(start 238.462312 -87.693754)
		(end 243.904516 -82.25155)
		(width 0.127)
		(layer "In13.Cu")
		(net "FM_PECI_MUX_SEL_N")
	)
	(segment
		(start 329.437746 -56.908446)
		(end 329.980036 -56.908446)
		(width 0.12954)
		(layer "F.Cu")
		(net "FM_PCIE_EV_BIF_EN")
	)
	(via
		(at 329.437746 -56.908446)
		(size 0.4572)
		(drill 0.2032)
		(layers "F.Cu" "B.Cu")
		(net "FM_PCIE_EV_BIF_EN")
	)
	(via
		(at 328.308716 -58.445654)
		(size 0.6604)
		(drill 0.3302)
		(layers "F.Cu" "B.Cu")
		(net "FM_PCIE_EV_BIF_EN")
	)
	(segment
		(start 329.436222 -57.318148)
		(end 328.308716 -58.445654)
		(width 0.12954)
		(layer "B.Cu")
		(net "FM_PCIE_EV_BIF_EN")
	)
	(segment
		(start 325.919592 -61.604906)
		(end 325.193914 -61.604906)
		(width 0.12954)
		(layer "B.Cu")
		(net "FM_PCIE_EV_BIF_EN")
	)
	(segment
		(start 328.308716 -58.445654)
		(end 328.308716 -59.237118)
		(width 0.12954)
		(layer "B.Cu")
		(net "FM_PCIE_EV_BIF_EN")
	)
	(segment
		(start 329.437746 -56.911748)
		(end 329.436222 -56.913272)
		(width 0.12954)
		(layer "B.Cu")
		(net "FM_PCIE_EV_BIF_EN")
	)
	(segment
		(start 329.436222 -56.913272)
		(end 329.436222 -57.318148)
		(width 0.12954)
		(layer "B.Cu")
		(net "FM_PCIE_EV_BIF_EN")
	)
	(segment
		(start 329.437746 -56.908446)
		(end 329.437746 -56.911748)
		(width 0.12954)
		(layer "B.Cu")
		(net "FM_PCIE_EV_BIF_EN")
	)
	(segment
		(start 328.308716 -59.237118)
		(end 326.187816 -61.358018)
		(width 0.12954)
		(layer "B.Cu")
		(net "FM_PCIE_EV_BIF_EN")
	)
	(segment
		(start 326.16648 -61.358018)
		(end 325.919592 -61.604906)
		(width 0.12954)
		(layer "B.Cu")
		(net "FM_PCIE_EV_BIF_EN")
	)
	(segment
		(start 326.187816 -61.358018)
		(end 326.16648 -61.358018)
		(width 0.12954)
		(layer "B.Cu")
		(net "FM_PCIE_EV_BIF_EN")
	)
	(segment
		(start 331.065378 -47.510446)
		(end 330.79436 -47.980346)
		(width 0.12954)
		(layer "F.Cu")
		(net "TP_GPP_L_8")
	)
	(via
		(at 326.618346 -49.883568)
		(size 0.6604)
		(drill 0.3302)
		(layers "F.Cu" "B.Cu")
		(net "TP_GPP_L_8")
	)
	(via
		(at 331.065378 -47.510446)
		(size 0.4572)
		(drill 0.2032)
		(layers "F.Cu" "B.Cu")
		(net "TP_GPP_L_8")
	)
	(segment
		(start 326.618346 -49.883568)
		(end 329.521566 -49.883568)
		(width 0.12954)
		(layer "B.Cu")
		(net "TP_GPP_L_8")
	)
	(segment
		(start 330.35113 -49.430178)
		(end 330.843128 -48.93818)
		(width 0.12954)
		(layer "B.Cu")
		(net "TP_GPP_L_8")
	)
	(segment
		(start 329.521566 -49.883568)
		(end 329.974956 -49.430178)
		(width 0.12954)
		(layer "B.Cu")
		(net "TP_GPP_L_8")
	)
	(segment
		(start 332.328774 -48.253142)
		(end 332.328774 -47.751746)
		(width 0.12954)
		(layer "B.Cu")
		(net "TP_GPP_L_8")
	)
	(segment
		(start 329.974956 -49.430178)
		(end 330.35113 -49.430178)
		(width 0.12954)
		(layer "B.Cu")
		(net "TP_GPP_L_8")
	)
	(segment
		(start 332.328774 -47.751746)
		(end 332.087474 -47.510446)
		(width 0.12954)
		(layer "B.Cu")
		(net "TP_GPP_L_8")
	)
	(segment
		(start 330.843128 -48.93818)
		(end 331.199998 -48.93818)
		(width 0.12954)
		(layer "B.Cu")
		(net "TP_GPP_L_8")
	)
	(segment
		(start 332.135734 -48.446182)
		(end 332.328774 -48.253142)
		(width 0.12954)
		(layer "B.Cu")
		(net "TP_GPP_L_8")
	)
	(segment
		(start 332.087474 -47.510446)
		(end 331.065378 -47.510446)
		(width 0.12954)
		(layer "B.Cu")
		(net "TP_GPP_L_8")
	)
	(segment
		(start 331.691996 -48.446182)
		(end 332.135734 -48.446182)
		(width 0.12954)
		(layer "B.Cu")
		(net "TP_GPP_L_8")
	)
	(segment
		(start 331.199998 -48.93818)
		(end 331.691996 -48.446182)
		(width 0.12954)
		(layer "B.Cu")
		(net "TP_GPP_L_8")
	)
	(segment
		(start 329.165966 -48.920146)
		(end 329.437746 -48.450246)
		(width 0.12954)
		(layer "F.Cu")
		(net "TP_GPP_L_7")
	)
	(via
		(at 329.437746 -48.450246)
		(size 0.4572)
		(drill 0.2032)
		(layers "F.Cu" "B.Cu")
		(net "TP_GPP_L_7")
	)
	(segment
		(start 331.065378 -48.450246)
		(end 330.92136 -48.450246)
		(width 0.12954)
		(layer "F.Cu")
		(net "TP_GPP_L_2")
	)
	(segment
		(start 330.79436 -48.577246)
		(end 330.79436 -48.920146)
		(width 0.12954)
		(layer "F.Cu")
		(net "TP_GPP_L_2")
	)
	(segment
		(start 330.92136 -48.450246)
		(end 330.79436 -48.577246)
		(width 0.12954)
		(layer "F.Cu")
		(net "TP_GPP_L_2")
	)
	(via
		(at 331.065378 -48.450246)
		(size 0.4572)
		(drill 0.2032)
		(layers "F.Cu" "B.Cu")
		(net "TP_GPP_L_2")
	)
	(segment
		(start 320.590672 -60.620148)
		(end 320.590672 -60.83173)
		(width 0.12954)
		(layer "F.Cu")
		(net "FM_PCH_XTAL_INPUT_MODE_MGPIO_TE")
	)
	(segment
		(start 326.30872 -56.230266)
		(end 326.719184 -56.230266)
		(width 0.0889)
		(layer "F.Cu")
		(net "FM_PCH_XTAL_INPUT_MODE_MGPIO_TE")
	)
	(segment
		(start 318.60998 -61.290708)
		(end 317.796672 -60.4774)
		(width 0.12954)
		(layer "F.Cu")
		(net "FM_PCH_XTAL_INPUT_MODE_MGPIO_TE")
	)
	(segment
		(start 322.111116 -60.782708)
		(end 325.003668 -57.890156)
		(width 0.12954)
		(layer "F.Cu")
		(net "FM_PCH_XTAL_INPUT_MODE_MGPIO_TE")
	)
	(segment
		(start 321.32016 -60.782708)
		(end 322.111116 -60.782708)
		(width 0.12954)
		(layer "F.Cu")
		(net "FM_PCH_XTAL_INPUT_MODE_MGPIO_TE")
	)
	(segment
		(start 318.7065 -61.194188)
		(end 318.60998 -61.290708)
		(width 0.12954)
		(layer "F.Cu")
		(net "FM_PCH_XTAL_INPUT_MODE_MGPIO_TE")
	)
	(segment
		(start 325.069454 -57.060084)
		(end 325.44893 -56.680608)
		(width 0.0889)
		(layer "F.Cu")
		(net "FM_PCH_XTAL_INPUT_MODE_MGPIO_TE")
	)
	(segment
		(start 325.003668 -57.12587)
		(end 325.069454 -57.060084)
		(width 0.12954)
		(layer "F.Cu")
		(net "FM_PCH_XTAL_INPUT_MODE_MGPIO_TE")
	)
	(segment
		(start 320.228214 -61.194188)
		(end 318.7065 -61.194188)
		(width 0.12954)
		(layer "F.Cu")
		(net "FM_PCH_XTAL_INPUT_MODE_MGPIO_TE")
	)
	(segment
		(start 321.1576 -60.620148)
		(end 321.32016 -60.782708)
		(width 0.12954)
		(layer "F.Cu")
		(net "FM_PCH_XTAL_INPUT_MODE_MGPIO_TE")
	)
	(segment
		(start 317.796672 -60.4774)
		(end 317.796672 -60.315348)
		(width 0.12954)
		(layer "F.Cu")
		(net "FM_PCH_XTAL_INPUT_MODE_MGPIO_TE")
	)
	(segment
		(start 326.719184 -56.230266)
		(end 327.13295 -55.953914)
		(width 0.0889)
		(layer "F.Cu")
		(net "FM_PCH_XTAL_INPUT_MODE_MGPIO_TE")
	)
	(segment
		(start 325.003668 -57.890156)
		(end 325.003668 -57.12587)
		(width 0.12954)
		(layer "F.Cu")
		(net "FM_PCH_XTAL_INPUT_MODE_MGPIO_TE")
	)
	(segment
		(start 327.13295 -55.953914)
		(end 327.41489 -55.953914)
		(width 0.0889)
		(layer "F.Cu")
		(net "FM_PCH_XTAL_INPUT_MODE_MGPIO_TE")
	)
	(segment
		(start 320.590672 -60.83173)
		(end 320.228214 -61.194188)
		(width 0.12954)
		(layer "F.Cu")
		(net "FM_PCH_XTAL_INPUT_MODE_MGPIO_TE")
	)
	(segment
		(start 320.590672 -60.620148)
		(end 321.1576 -60.620148)
		(width 0.12954)
		(layer "F.Cu")
		(net "FM_PCH_XTAL_INPUT_MODE_MGPIO_TE")
	)
	(segment
		(start 325.858378 -56.680608)
		(end 326.30872 -56.230266)
		(width 0.0889)
		(layer "F.Cu")
		(net "FM_PCH_XTAL_INPUT_MODE_MGPIO_TE")
	)
	(segment
		(start 325.44893 -56.680608)
		(end 325.858378 -56.680608)
		(width 0.0889)
		(layer "F.Cu")
		(net "FM_PCH_XTAL_INPUT_MODE_MGPIO_TE")
	)
	(via
		(at 318.60998 -61.290708)
		(size 0.508)
		(drill 0.254)
		(layers "F.Cu" "B.Cu")
		(net "FM_PCH_XTAL_INPUT_MODE_MGPIO_TE")
	)
	(segment
		(start 327.829926 -52.45227)
		(end 327.495154 -52.45227)
		(width 0.0889)
		(layer "F.Cu")
		(net "FM_PCH_XTALSEL")
	)
	(segment
		(start 326.88276 -52.754022)
		(end 326.751188 -52.666392)
		(width 0.0889)
		(layer "F.Cu")
		(net "FM_PCH_XTALSEL")
	)
	(segment
		(start 315.790072 -54.498748)
		(end 315.510672 -54.219348)
		(width 0.12954)
		(layer "F.Cu")
		(net "FM_PCH_XTALSEL")
	)
	(segment
		(start 323.43725 -53.304948)
		(end 322.381118 -54.36108)
		(width 0.12954)
		(layer "F.Cu")
		(net "FM_PCH_XTALSEL")
	)
	(segment
		(start 323.958966 -52.666392)
		(end 323.597016 -53.028342)
		(width 0.0889)
		(layer "F.Cu")
		(net "FM_PCH_XTALSEL")
	)
	(segment
		(start 317.314072 -54.320948)
		(end 316.71768 -54.320948)
		(width 0.12954)
		(layer "F.Cu")
		(net "FM_PCH_XTALSEL")
	)
	(segment
		(start 319.624456 -54.125368)
		(end 319.523364 -54.024276)
		(width 0.12954)
		(layer "F.Cu")
		(net "FM_PCH_XTALSEL")
	)
	(segment
		(start 322.381118 -54.36108)
		(end 321.092068 -54.36108)
		(width 0.12954)
		(layer "F.Cu")
		(net "FM_PCH_XTALSEL")
	)
	(segment
		(start 317.796672 -54.803548)
		(end 317.314072 -54.320948)
		(width 0.12954)
		(layer "F.Cu")
		(net "FM_PCH_XTALSEL")
	)
	(segment
		(start 316.71768 -54.320948)
		(end 316.53988 -54.498748)
		(width 0.12954)
		(layer "F.Cu")
		(net "FM_PCH_XTALSEL")
	)
	(segment
		(start 323.43725 -53.188108)
		(end 323.43725 -53.304948)
		(width 0.12954)
		(layer "F.Cu")
		(net "FM_PCH_XTALSEL")
	)
	(segment
		(start 319.012316 -54.024276)
		(end 318.575944 -54.024276)
		(width 0.12954)
		(layer "F.Cu")
		(net "FM_PCH_XTALSEL")
	)
	(segment
		(start 320.856356 -54.125368)
		(end 319.624456 -54.125368)
		(width 0.12954)
		(layer "F.Cu")
		(net "FM_PCH_XTALSEL")
	)
	(segment
		(start 319.523364 -54.024276)
		(end 319.012316 -54.024276)
		(width 0.12954)
		(layer "F.Cu")
		(net "FM_PCH_XTALSEL")
	)
	(segment
		(start 316.53988 -54.498748)
		(end 315.790072 -54.498748)
		(width 0.12954)
		(layer "F.Cu")
		(net "FM_PCH_XTALSEL")
	)
	(segment
		(start 318.575944 -54.024276)
		(end 317.796672 -54.803548)
		(width 0.12954)
		(layer "F.Cu")
		(net "FM_PCH_XTALSEL")
	)
	(segment
		(start 323.597016 -53.028342)
		(end 323.43725 -53.188108)
		(width 0.12954)
		(layer "F.Cu")
		(net "FM_PCH_XTALSEL")
	)
	(segment
		(start 327.495154 -52.45227)
		(end 327.145396 -52.754022)
		(width 0.0889)
		(layer "F.Cu")
		(net "FM_PCH_XTALSEL")
	)
	(segment
		(start 321.092068 -54.36108)
		(end 320.856356 -54.125368)
		(width 0.12954)
		(layer "F.Cu")
		(net "FM_PCH_XTALSEL")
	)
	(segment
		(start 326.751188 -52.666392)
		(end 323.958966 -52.666392)
		(width 0.0889)
		(layer "F.Cu")
		(net "FM_PCH_XTALSEL")
	)
	(segment
		(start 327.145396 -52.754022)
		(end 326.88276 -52.754022)
		(width 0.0889)
		(layer "F.Cu")
		(net "FM_PCH_XTALSEL")
	)
	(via
		(at 319.012316 -54.024276)
		(size 0.762)
		(drill 0.381)
		(layers "F.Cu" "B.Cu")
		(net "FM_PCH_XTALSEL")
	)
	(segment
		(start 327.829926 -56.45404)
		(end 327.467976 -56.45404)
		(width 0.0889)
		(layer "F.Cu")
		(net "FM_PCH_VISA_DEFAULT")
	)
	(segment
		(start 321.01663 -62.880748)
		(end 320.590672 -62.880748)
		(width 0.12954)
		(layer "F.Cu")
		(net "FM_PCH_VISA_DEFAULT")
	)
	(segment
		(start 321.74561 -62.151768)
		(end 321.01663 -62.880748)
		(width 0.12954)
		(layer "F.Cu")
		(net "FM_PCH_VISA_DEFAULT")
	)
	(segment
		(start 327.295256 -56.62676)
		(end 327.1012 -56.7944)
		(width 0.0889)
		(layer "F.Cu")
		(net "FM_PCH_VISA_DEFAULT")
	)
	(segment
		(start 322.26123 -61.636148)
		(end 321.74561 -62.151768)
		(width 0.12954)
		(layer "F.Cu")
		(net "FM_PCH_VISA_DEFAULT")
	)
	(segment
		(start 327.467976 -56.45404)
		(end 327.295256 -56.62676)
		(width 0.0889)
		(layer "F.Cu")
		(net "FM_PCH_VISA_DEFAULT")
	)
	(segment
		(start 327.1012 -56.962294)
		(end 326.204326 -57.761632)
		(width 0.0889)
		(layer "F.Cu")
		(net "FM_PCH_VISA_DEFAULT")
	)
	(segment
		(start 327.1012 -56.7944)
		(end 327.1012 -56.962294)
		(width 0.0889)
		(layer "F.Cu")
		(net "FM_PCH_VISA_DEFAULT")
	)
	(segment
		(start 325.958454 -58.007504)
		(end 322.32981 -61.636148)
		(width 0.12954)
		(layer "F.Cu")
		(net "FM_PCH_VISA_DEFAULT")
	)
	(segment
		(start 326.204326 -57.761632)
		(end 325.958454 -58.007504)
		(width 0.0889)
		(layer "F.Cu")
		(net "FM_PCH_VISA_DEFAULT")
	)
	(segment
		(start 322.32981 -61.636148)
		(end 322.26123 -61.636148)
		(width 0.12954)
		(layer "F.Cu")
		(net "FM_PCH_VISA_DEFAULT")
	)
	(via
		(at 321.74561 -62.151768)
		(size 0.508)
		(drill 0.254)
		(layers "F.Cu" "B.Cu")
		(net "FM_PCH_VISA_DEFAULT")
	)
	(segment
		(start 329.437746 -55.028846)
		(end 329.980036 -55.028846)
		(width 0.12954)
		(layer "F.Cu")
		(net "FM_PCH_TRIGGER1_R_N")
	)
	(via
		(at 329.437746 -55.028846)
		(size 0.4572)
		(drill 0.2032)
		(layers "F.Cu" "B.Cu")
		(net "FM_PCH_TRIGGER1_R_N")
	)
	(via
		(at 326.233282 -54.803548)
		(size 0.6604)
		(drill 0.3302)
		(layers "F.Cu" "B.Cu")
		(net "FM_PCH_TRIGGER1_R_N")
	)
	(segment
		(start 315.51753 -56.276748)
		(end 315.51753 -55.242206)
		(width 0.12954)
		(layer "B.Cu")
		(net "FM_PCH_TRIGGER1_R_N")
	)
	(segment
		(start 318.69888 -53.889148)
		(end 317.47968 -55.108348)
		(width 0.12954)
		(layer "B.Cu")
		(net "FM_PCH_TRIGGER1_R_N")
	)
	(segment
		(start 317.47968 -55.108348)
		(end 315.637672 -55.108348)
		(width 0.12954)
		(layer "B.Cu")
		(net "FM_PCH_TRIGGER1_R_N")
	)
	(segment
		(start 315.637672 -55.108348)
		(end 315.510672 -55.235348)
		(width 0.12954)
		(layer "B.Cu")
		(net "FM_PCH_TRIGGER1_R_N")
	)
	(segment
		(start 329.437746 -55.028846)
		(end 328.40295 -55.028846)
		(width 0.12954)
		(layer "B.Cu")
		(net "FM_PCH_TRIGGER1_R_N")
	)
	(segment
		(start 325.868538 -54.803548)
		(end 324.877938 -53.812948)
		(width 0.12954)
		(layer "B.Cu")
		(net "FM_PCH_TRIGGER1_R_N")
	)
	(segment
		(start 320.24828 -53.889148)
		(end 318.69888 -53.889148)
		(width 0.12954)
		(layer "B.Cu")
		(net "FM_PCH_TRIGGER1_R_N")
	)
	(segment
		(start 328.177652 -54.803548)
		(end 326.233282 -54.803548)
		(width 0.12954)
		(layer "B.Cu")
		(net "FM_PCH_TRIGGER1_R_N")
	)
	(segment
		(start 328.40295 -55.028846)
		(end 328.177652 -54.803548)
		(width 0.12954)
		(layer "B.Cu")
		(net "FM_PCH_TRIGGER1_R_N")
	)
	(segment
		(start 320.55308 -53.584348)
		(end 320.24828 -53.889148)
		(width 0.12954)
		(layer "B.Cu")
		(net "FM_PCH_TRIGGER1_R_N")
	)
	(segment
		(start 324.877938 -53.812948)
		(end 323.815202 -53.812948)
		(width 0.12954)
		(layer "B.Cu")
		(net "FM_PCH_TRIGGER1_R_N")
	)
	(segment
		(start 315.51753 -55.242206)
		(end 315.510672 -55.235348)
		(width 0.12954)
		(layer "B.Cu")
		(net "FM_PCH_TRIGGER1_R_N")
	)
	(segment
		(start 323.815202 -53.812948)
		(end 323.586602 -53.584348)
		(width 0.12954)
		(layer "B.Cu")
		(net "FM_PCH_TRIGGER1_R_N")
	)
	(segment
		(start 323.586602 -53.584348)
		(end 320.55308 -53.584348)
		(width 0.12954)
		(layer "B.Cu")
		(net "FM_PCH_TRIGGER1_R_N")
	)
	(segment
		(start 326.233282 -54.803548)
		(end 325.868538 -54.803548)
		(width 0.12954)
		(layer "B.Cu")
		(net "FM_PCH_TRIGGER1_R_N")
	)
	(via
		(at 314.10148 -56.276748)
		(size 0.508)
		(drill 0.254)
		(layers "F.Cu" "B.Cu")
		(net "FM_PCH_TRIGGER1_N")
	)
	(via
		(at 303.96688 -64.099948)
		(size 0.508)
		(drill 0.254)
		(layers "F.Cu" "B.Cu")
		(net "FM_PCH_TRIGGER1_N")
	)
	(via
		(at 287.96488 -163.286948)
		(size 0.762)
		(drill 0.254)
		(layers "F.Cu" "B.Cu")
		(net "FM_PCH_TRIGGER1_N")
	)
	(segment
		(start 287.96488 -163.286948)
		(end 287.96488 -162.651948)
		(width 0.12954)
		(layer "B.Cu")
		(net "FM_PCH_TRIGGER1_N")
	)
	(segment
		(start 314.10148 -56.022748)
		(end 314.710572 -55.413656)
		(width 0.12954)
		(layer "B.Cu")
		(net "FM_PCH_TRIGGER1_N")
	)
	(segment
		(start 287.96488 -162.651948)
		(end 290.90874 -159.708088)
		(width 0.12954)
		(layer "B.Cu")
		(net "FM_PCH_TRIGGER1_N")
	)
	(segment
		(start 320.533268 -170.043856)
		(end 325.133208 -170.043856)
		(width 0.12954)
		(layer "B.Cu")
		(net "FM_PCH_TRIGGER1_N")
	)
	(segment
		(start 290.90874 -159.708088)
		(end 310.1975 -159.708088)
		(width 0.12954)
		(layer "B.Cu")
		(net "FM_PCH_TRIGGER1_N")
	)
	(segment
		(start 310.1975 -159.708088)
		(end 320.533268 -170.043856)
		(width 0.12954)
		(layer "B.Cu")
		(net "FM_PCH_TRIGGER1_N")
	)
	(segment
		(start 335.741264 -180.651912)
		(end 335.741264 -184.427876)
		(width 0.12954)
		(layer "B.Cu")
		(net "FM_PCH_TRIGGER1_N")
	)
	(segment
		(start 325.133208 -170.043856)
		(end 335.741264 -180.651912)
		(width 0.12954)
		(layer "B.Cu")
		(net "FM_PCH_TRIGGER1_N")
	)
	(segment
		(start 314.710572 -55.413656)
		(end 314.710572 -55.235348)
		(width 0.12954)
		(layer "B.Cu")
		(net "FM_PCH_TRIGGER1_N")
	)
	(segment
		(start 314.10148 -56.276748)
		(end 314.10148 -56.022748)
		(width 0.12954)
		(layer "B.Cu")
		(net "FM_PCH_TRIGGER1_N")
	)
	(segment
		(start 303.96688 -64.099948)
		(end 303.96688 -64.988948)
		(width 0.127)
		(layer "In2.Cu")
		(net "FM_PCH_TRIGGER1_N")
	)
	(segment
		(start 298.99864 -155.169108)
		(end 294.064182 -157.213046)
		(width 0.127)
		(layer "In2.Cu")
		(net "FM_PCH_TRIGGER1_N")
	)
	(segment
		(start 304.14468 -65.166748)
		(end 304.14468 -70.322948)
		(width 0.127)
		(layer "In2.Cu")
		(net "FM_PCH_TRIGGER1_N")
	)
	(segment
		(start 287.96488 -162.397948)
		(end 287.96488 -163.286948)
		(width 0.127)
		(layer "In2.Cu")
		(net "FM_PCH_TRIGGER1_N")
	)
	(segment
		(start 288.12998 -161.420048)
		(end 288.12998 -162.232848)
		(width 0.127)
		(layer "In2.Cu")
		(net "FM_PCH_TRIGGER1_N")
	)
	(segment
		(start 294.064182 -157.213046)
		(end 293.80688 -157.470348)
		(width 0.127)
		(layer "In2.Cu")
		(net "FM_PCH_TRIGGER1_N")
	)
	(segment
		(start 304.14468 -70.322948)
		(end 306.73548 -72.913748)
		(width 0.127)
		(layer "In2.Cu")
		(net "FM_PCH_TRIGGER1_N")
	)
	(segment
		(start 293.80688 -157.470348)
		(end 292.07968 -157.470348)
		(width 0.127)
		(layer "In2.Cu")
		(net "FM_PCH_TRIGGER1_N")
	)
	(segment
		(start 306.73548 -72.913748)
		(end 306.73548 -128.0414)
		(width 0.127)
		(layer "In2.Cu")
		(net "FM_PCH_TRIGGER1_N")
	)
	(segment
		(start 303.96688 -64.988948)
		(end 304.14468 -65.166748)
		(width 0.127)
		(layer "In2.Cu")
		(net "FM_PCH_TRIGGER1_N")
	)
	(segment
		(start 301.12208 -133.6548)
		(end 301.12208 -153.045668)
		(width 0.127)
		(layer "In2.Cu")
		(net "FM_PCH_TRIGGER1_N")
	)
	(segment
		(start 292.07968 -157.470348)
		(end 288.12998 -161.420048)
		(width 0.127)
		(layer "In2.Cu")
		(net "FM_PCH_TRIGGER1_N")
	)
	(segment
		(start 301.12208 -153.045668)
		(end 298.99864 -155.169108)
		(width 0.127)
		(layer "In2.Cu")
		(net "FM_PCH_TRIGGER1_N")
	)
	(segment
		(start 288.12998 -162.232848)
		(end 287.96488 -162.397948)
		(width 0.127)
		(layer "In2.Cu")
		(net "FM_PCH_TRIGGER1_N")
	)
	(segment
		(start 306.73548 -128.0414)
		(end 301.12208 -133.6548)
		(width 0.127)
		(layer "In2.Cu")
		(net "FM_PCH_TRIGGER1_N")
	)
	(segment
		(start 311.342024 -60.801758)
		(end 306.17287 -60.801758)
		(width 0.127)
		(layer "In11.Cu")
		(net "FM_PCH_TRIGGER1_N")
	)
	(segment
		(start 314.10148 -56.276748)
		(end 314.10148 -58.042302)
		(width 0.127)
		(layer "In11.Cu")
		(net "FM_PCH_TRIGGER1_N")
	)
	(segment
		(start 306.17287 -60.801758)
		(end 303.96688 -63.007748)
		(width 0.127)
		(layer "In11.Cu")
		(net "FM_PCH_TRIGGER1_N")
	)
	(segment
		(start 303.96688 -63.007748)
		(end 303.96688 -64.099948)
		(width 0.127)
		(layer "In11.Cu")
		(net "FM_PCH_TRIGGER1_N")
	)
	(segment
		(start 314.10148 -58.042302)
		(end 311.342024 -60.801758)
		(width 0.127)
		(layer "In11.Cu")
		(net "FM_PCH_TRIGGER1_N")
	)
	(segment
		(start 331.069188 -55.968646)
		(end 331.608176 -55.968646)
		(width 0.12954)
		(layer "F.Cu")
		(net "FM_PCH_TRIGGER0_R_N")
	)
	(via
		(at 326.489822 -56.454548)
		(size 0.6604)
		(drill 0.3302)
		(layers "F.Cu" "B.Cu")
		(net "FM_PCH_TRIGGER0_R_N")
	)
	(via
		(at 331.069188 -55.968646)
		(size 0.4572)
		(drill 0.2032)
		(layers "F.Cu" "B.Cu")
		(net "FM_PCH_TRIGGER0_R_N")
	)
	(segment
		(start 331.069188 -55.968646)
		(end 328.366628 -55.968646)
		(width 0.12954)
		(layer "B.Cu")
		(net "FM_PCH_TRIGGER0_R_N")
	)
	(segment
		(start 326.16267 -56.7817)
		(end 323.87032 -56.7817)
		(width 0.12954)
		(layer "B.Cu")
		(net "FM_PCH_TRIGGER0_R_N")
	)
	(segment
		(start 326.809608 -56.134762)
		(end 326.489822 -56.454548)
		(width 0.12954)
		(layer "B.Cu")
		(net "FM_PCH_TRIGGER0_R_N")
	)
	(segment
		(start 326.489822 -56.454548)
		(end 326.16267 -56.7817)
		(width 0.12954)
		(layer "B.Cu")
		(net "FM_PCH_TRIGGER0_R_N")
	)
	(segment
		(start 323.87032 -56.7817)
		(end 323.384672 -57.267348)
		(width 0.12954)
		(layer "B.Cu")
		(net "FM_PCH_TRIGGER0_R_N")
	)
	(segment
		(start 328.200512 -56.134762)
		(end 326.809608 -56.134762)
		(width 0.12954)
		(layer "B.Cu")
		(net "FM_PCH_TRIGGER0_R_N")
	)
	(segment
		(start 323.384672 -58.283348)
		(end 323.384672 -57.267348)
		(width 0.12954)
		(layer "B.Cu")
		(net "FM_PCH_TRIGGER0_R_N")
	)
	(segment
		(start 328.366628 -55.968646)
		(end 328.200512 -56.134762)
		(width 0.12954)
		(layer "B.Cu")
		(net "FM_PCH_TRIGGER0_R_N")
	)
	(via
		(at 288.72688 -162.905948)
		(size 0.508)
		(drill 0.254)
		(layers "F.Cu" "B.Cu")
		(net "FM_PCH_TRIGGER0_N")
	)
	(via
		(at 304.72888 -64.099948)
		(size 0.508)
		(drill 0.254)
		(layers "F.Cu" "B.Cu")
		(net "FM_PCH_TRIGGER0_N")
	)
	(via
		(at 321.974972 -57.247028)
		(size 0.508)
		(drill 0.254)
		(layers "F.Cu" "B.Cu")
		(net "FM_PCH_TRIGGER0_N")
	)
	(segment
		(start 320.855848 -171.311062)
		(end 325.369428 -171.311062)
		(width 0.12954)
		(layer "B.Cu")
		(net "FM_PCH_TRIGGER0_N")
	)
	(segment
		(start 325.369428 -171.311062)
		(end 334.115918 -180.057552)
		(width 0.12954)
		(layer "B.Cu")
		(net "FM_PCH_TRIGGER0_N")
	)
	(segment
		(start 321.995292 -57.267348)
		(end 322.584572 -57.267348)
		(width 0.12954)
		(layer "B.Cu")
		(net "FM_PCH_TRIGGER0_N")
	)
	(segment
		(start 288.72688 -162.905948)
		(end 291.53485 -160.097978)
		(width 0.12954)
		(layer "B.Cu")
		(net "FM_PCH_TRIGGER0_N")
	)
	(segment
		(start 334.115918 -180.057552)
		(end 334.115918 -185.54954)
		(width 0.12954)
		(layer "B.Cu")
		(net "FM_PCH_TRIGGER0_N")
	)
	(segment
		(start 334.115918 -185.54954)
		(end 334.335628 -185.76925)
		(width 0.12954)
		(layer "B.Cu")
		(net "FM_PCH_TRIGGER0_N")
	)
	(segment
		(start 291.53485 -160.097978)
		(end 309.642764 -160.097978)
		(width 0.12954)
		(layer "B.Cu")
		(net "FM_PCH_TRIGGER0_N")
	)
	(segment
		(start 309.642764 -160.097978)
		(end 320.855848 -171.311062)
		(width 0.12954)
		(layer "B.Cu")
		(net "FM_PCH_TRIGGER0_N")
	)
	(segment
		(start 321.974972 -57.247028)
		(end 321.995292 -57.267348)
		(width 0.12954)
		(layer "B.Cu")
		(net "FM_PCH_TRIGGER0_N")
	)
	(segment
		(start 288.56178 -162.232848)
		(end 288.72688 -162.397948)
		(width 0.127)
		(layer "In2.Cu")
		(net "FM_PCH_TRIGGER0_N")
	)
	(segment
		(start 288.56178 -161.599118)
		(end 288.56178 -162.232848)
		(width 0.127)
		(layer "In2.Cu")
		(net "FM_PCH_TRIGGER0_N")
	)
	(segment
		(start 304.57648 -65.141348)
		(end 304.57648 -70.143878)
		(width 0.127)
		(layer "In2.Cu")
		(net "FM_PCH_TRIGGER0_N")
	)
	(segment
		(start 294.128698 -157.7594)
		(end 293.98595 -157.902148)
		(width 0.127)
		(layer "In2.Cu")
		(net "FM_PCH_TRIGGER0_N")
	)
	(segment
		(start 293.98595 -157.902148)
		(end 292.25875 -157.902148)
		(width 0.127)
		(layer "In2.Cu")
		(net "FM_PCH_TRIGGER0_N")
	)
	(segment
		(start 304.57648 -70.143878)
		(end 307.16728 -72.734678)
		(width 0.127)
		(layer "In2.Cu")
		(net "FM_PCH_TRIGGER0_N")
	)
	(segment
		(start 301.696374 -153.259028)
		(end 299.365162 -155.59024)
		(width 0.127)
		(layer "In2.Cu")
		(net "FM_PCH_TRIGGER0_N")
	)
	(segment
		(start 304.72888 -64.099948)
		(end 304.72888 -64.988948)
		(width 0.127)
		(layer "In2.Cu")
		(net "FM_PCH_TRIGGER0_N")
	)
	(segment
		(start 307.16728 -72.734678)
		(end 307.16728 -128.7018)
		(width 0.127)
		(layer "In2.Cu")
		(net "FM_PCH_TRIGGER0_N")
	)
	(segment
		(start 292.25875 -157.902148)
		(end 288.56178 -161.599118)
		(width 0.127)
		(layer "In2.Cu")
		(net "FM_PCH_TRIGGER0_N")
	)
	(segment
		(start 288.72688 -162.397948)
		(end 288.72688 -162.905948)
		(width 0.127)
		(layer "In2.Cu")
		(net "FM_PCH_TRIGGER0_N")
	)
	(segment
		(start 304.72888 -64.988948)
		(end 304.57648 -65.141348)
		(width 0.127)
		(layer "In2.Cu")
		(net "FM_PCH_TRIGGER0_N")
	)
	(segment
		(start 301.696374 -134.172706)
		(end 301.696374 -153.259028)
		(width 0.127)
		(layer "In2.Cu")
		(net "FM_PCH_TRIGGER0_N")
	)
	(segment
		(start 307.16728 -128.7018)
		(end 301.696374 -134.172706)
		(width 0.127)
		(layer "In2.Cu")
		(net "FM_PCH_TRIGGER0_N")
	)
	(segment
		(start 299.365162 -155.59024)
		(end 294.128698 -157.7594)
		(width 0.127)
		(layer "In2.Cu")
		(net "FM_PCH_TRIGGER0_N")
	)
	(segment
		(start 318.03848 -56.759348)
		(end 317.63208 -56.352948)
		(width 0.127)
		(layer "In11.Cu")
		(net "FM_PCH_TRIGGER0_N")
	)
	(segment
		(start 304.72888 -63.160148)
		(end 304.72888 -64.099948)
		(width 0.127)
		(layer "In11.Cu")
		(net "FM_PCH_TRIGGER0_N")
	)
	(segment
		(start 306.55768 -61.331348)
		(end 304.72888 -63.160148)
		(width 0.127)
		(layer "In11.Cu")
		(net "FM_PCH_TRIGGER0_N")
	)
	(segment
		(start 317.63208 -56.352948)
		(end 315.93028 -56.352948)
		(width 0.127)
		(layer "In11.Cu")
		(net "FM_PCH_TRIGGER0_N")
	)
	(segment
		(start 315.67628 -56.606948)
		(end 315.67628 -57.153048)
		(width 0.127)
		(layer "In11.Cu")
		(net "FM_PCH_TRIGGER0_N")
	)
	(segment
		(start 315.93028 -56.352948)
		(end 315.67628 -56.606948)
		(width 0.127)
		(layer "In11.Cu")
		(net "FM_PCH_TRIGGER0_N")
	)
	(segment
		(start 311.49798 -61.331348)
		(end 306.55768 -61.331348)
		(width 0.127)
		(layer "In11.Cu")
		(net "FM_PCH_TRIGGER0_N")
	)
	(segment
		(start 321.974972 -57.247028)
		(end 321.487292 -56.759348)
		(width 0.127)
		(layer "In11.Cu")
		(net "FM_PCH_TRIGGER0_N")
	)
	(segment
		(start 321.487292 -56.759348)
		(end 318.03848 -56.759348)
		(width 0.127)
		(layer "In11.Cu")
		(net "FM_PCH_TRIGGER0_N")
	)
	(segment
		(start 315.67628 -57.153048)
		(end 311.49798 -61.331348)
		(width 0.127)
		(layer "In11.Cu")
		(net "FM_PCH_TRIGGER0_N")
	)
	(segment
		(start 330.79436 -44.221146)
		(end 330.253848 -44.221146)
		(width 0.12954)
		(layer "F.Cu")
		(net "FM_PCH_SPARE0")
	)
	(via
		(at 330.253848 -44.221146)
		(size 0.4572)
		(drill 0.2032)
		(layers "F.Cu" "B.Cu")
		(net "FM_PCH_SPARE0")
	)
	(via
		(at 318.64808 -29.352748)
		(size 0.6604)
		(drill 0.3302)
		(layers "F.Cu" "B.Cu")
		(net "FM_PCH_SPARE0")
	)
	(segment
		(start 318.64808 -29.8577)
		(end 318.64808 -29.352748)
		(width 0.12954)
		(layer "B.Cu")
		(net "FM_PCH_SPARE0")
	)
	(segment
		(start 324.239128 -37.871654)
		(end 321.140582 -34.773108)
		(width 0.12954)
		(layer "B.Cu")
		(net "FM_PCH_SPARE0")
	)
	(segment
		(start 326.327262 -41.330372)
		(end 326.060308 -40.686228)
		(width 0.12954)
		(layer "B.Cu")
		(net "FM_PCH_SPARE0")
	)
	(segment
		(start 324.239128 -38.224206)
		(end 324.239128 -37.871654)
		(width 0.12954)
		(layer "B.Cu")
		(net "FM_PCH_SPARE0")
	)
	(segment
		(start 321.140582 -34.773108)
		(end 320.133218 -34.773108)
		(width 0.12954)
		(layer "B.Cu")
		(net "FM_PCH_SPARE0")
	)
	(segment
		(start 329.598782 -43.297348)
		(end 329.334622 -43.297348)
		(width 0.12954)
		(layer "B.Cu")
		(net "FM_PCH_SPARE0")
	)
	(segment
		(start 330.253848 -43.952414)
		(end 329.598782 -43.297348)
		(width 0.12954)
		(layer "B.Cu")
		(net "FM_PCH_SPARE0")
	)
	(segment
		(start 320.133218 -34.773108)
		(end 319.040256 -33.680146)
		(width 0.12954)
		(layer "B.Cu")
		(net "FM_PCH_SPARE0")
	)
	(segment
		(start 330.253848 -44.221146)
		(end 330.253848 -43.952414)
		(width 0.12954)
		(layer "B.Cu")
		(net "FM_PCH_SPARE0")
	)
	(segment
		(start 318.64808 -29.352748)
		(end 318.30264 -29.698188)
		(width 0.12954)
		(layer "B.Cu")
		(net "FM_PCH_SPARE0")
	)
	(segment
		(start 328.843894 -42.80662)
		(end 327.80351 -42.80662)
		(width 0.12954)
		(layer "B.Cu")
		(net "FM_PCH_SPARE0")
	)
	(segment
		(start 325.563992 -40.189912)
		(end 325.563992 -39.54907)
		(width 0.12954)
		(layer "B.Cu")
		(net "FM_PCH_SPARE0")
	)
	(segment
		(start 319.040256 -33.680146)
		(end 319.040256 -30.249876)
		(width 0.12954)
		(layer "B.Cu")
		(net "FM_PCH_SPARE0")
	)
	(segment
		(start 327.80351 -42.80662)
		(end 326.327262 -41.330372)
		(width 0.12954)
		(layer "B.Cu")
		(net "FM_PCH_SPARE0")
	)
	(segment
		(start 325.563992 -39.54907)
		(end 324.239128 -38.224206)
		(width 0.12954)
		(layer "B.Cu")
		(net "FM_PCH_SPARE0")
	)
	(segment
		(start 319.040256 -30.249876)
		(end 318.64808 -29.8577)
		(width 0.12954)
		(layer "B.Cu")
		(net "FM_PCH_SPARE0")
	)
	(segment
		(start 326.060308 -40.686228)
		(end 325.563992 -40.189912)
		(width 0.12954)
		(layer "B.Cu")
		(net "FM_PCH_SPARE0")
	)
	(segment
		(start 329.334622 -43.297348)
		(end 328.843894 -42.80662)
		(width 0.12954)
		(layer "B.Cu")
		(net "FM_PCH_SPARE0")
	)
	(segment
		(start 318.30264 -29.698188)
		(end 318.30264 -30.507178)
		(width 0.12954)
		(layer "B.Cu")
		(net "FM_PCH_SPARE0")
	)
	(segment
		(start 329.437746 -44.691046)
		(end 329.32751 -44.691046)
		(width 0.12954)
		(layer "F.Cu")
		(net "FM_PCH_SLP_SUS_N")
	)
	(segment
		(start 329.32751 -44.691046)
		(end 329.165966 -44.85259)
		(width 0.12954)
		(layer "F.Cu")
		(net "FM_PCH_SLP_SUS_N")
	)
	(segment
		(start 329.165966 -44.85259)
		(end 329.165966 -45.160946)
		(width 0.12954)
		(layer "F.Cu")
		(net "FM_PCH_SLP_SUS_N")
	)
	(via
		(at 324.48246 -42.150284)
		(size 0.6604)
		(drill 0.3302)
		(layers "F.Cu" "B.Cu")
		(net "FM_PCH_SLP_SUS_N")
	)
	(via
		(at 329.437746 -44.691046)
		(size 0.4572)
		(drill 0.2032)
		(layers "F.Cu" "B.Cu")
		(net "FM_PCH_SLP_SUS_N")
	)
	(segment
		(start 328.957178 -44.210478)
		(end 328.125836 -44.210478)
		(width 0.0889)
		(layer "B.Cu")
		(net "FM_PCH_SLP_SUS_N")
	)
	(segment
		(start 323.685916 -40.956738)
		(end 323.685916 -40.274748)
		(width 0.12954)
		(layer "B.Cu")
		(net "FM_PCH_SLP_SUS_N")
	)
	(segment
		(start 324.48246 -42.150284)
		(end 324.47484 -42.142664)
		(width 0.12954)
		(layer "B.Cu")
		(net "FM_PCH_SLP_SUS_N")
	)
	(segment
		(start 323.685916 -40.274748)
		(end 323.288152 -39.876984)
		(width 0.12954)
		(layer "B.Cu")
		(net "FM_PCH_SLP_SUS_N")
	)
	(segment
		(start 324.47484 -42.142664)
		(end 324.352412 -41.847008)
		(width 0.12954)
		(layer "B.Cu")
		(net "FM_PCH_SLP_SUS_N")
	)
	(segment
		(start 324.193916 -41.464738)
		(end 323.685916 -40.956738)
		(width 0.12954)
		(layer "B.Cu")
		(net "FM_PCH_SLP_SUS_N")
	)
	(segment
		(start 328.125836 -44.210478)
		(end 326.542654 -44.210478)
		(width 0.12954)
		(layer "B.Cu")
		(net "FM_PCH_SLP_SUS_N")
	)
	(segment
		(start 329.437746 -44.691046)
		(end 328.957178 -44.210478)
		(width 0.0889)
		(layer "B.Cu")
		(net "FM_PCH_SLP_SUS_N")
	)
	(segment
		(start 326.542654 -44.210478)
		(end 324.48246 -42.150284)
		(width 0.12954)
		(layer "B.Cu")
		(net "FM_PCH_SLP_SUS_N")
	)
	(segment
		(start 324.352412 -41.847008)
		(end 324.193916 -41.464738)
		(width 0.12954)
		(layer "B.Cu")
		(net "FM_PCH_SLP_SUS_N")
	)
	(segment
		(start 323.162422 -39.876984)
		(end 322.363338 -39.0779)
		(width 0.12954)
		(layer "B.Cu")
		(net "FM_PCH_SLP_SUS_N")
	)
	(segment
		(start 323.288152 -39.876984)
		(end 323.162422 -39.876984)
		(width 0.12954)
		(layer "B.Cu")
		(net "FM_PCH_SLP_SUS_N")
	)
	(segment
		(start 108.956348 -102.943152)
		(end 109.70768 -102.943152)
		(width 0.12954)
		(layer "F.Cu")
		(net "FM_PCH_SLP_S4_N")
	)
	(segment
		(start 332.422246 -45.160946)
		(end 332.693518 -44.691046)
		(width 0.12954)
		(layer "F.Cu")
		(net "FM_PCH_SLP_S4_N")
	)
	(via
		(at 286.63519 -50.332386)
		(size 0.508)
		(drill 0.254)
		(layers "F.Cu" "B.Cu")
		(net "FM_PCH_SLP_S4_N")
	)
	(via
		(at 332.693518 -44.691046)
		(size 0.4572)
		(drill 0.2032)
		(layers "F.Cu" "B.Cu")
		(net "FM_PCH_SLP_S4_N")
	)
	(via
		(at 109.70768 -102.943152)
		(size 0.508)
		(drill 0.254)
		(layers "F.Cu" "B.Cu")
		(net "FM_PCH_SLP_S4_N")
	)
	(via
		(at 321.799204 -29.986478)
		(size 0.6604)
		(drill 0.3302)
		(layers "F.Cu" "B.Cu")
		(net "FM_PCH_SLP_S4_N")
	)
	(segment
		(start 332.693518 -44.691046)
		(end 331.738224 -44.691046)
		(width 0.0889)
		(layer "B.Cu")
		(net "FM_PCH_SLP_S4_N")
	)
	(segment
		(start 327.281286 -38.40734)
		(end 326.174862 -37.300916)
		(width 0.12954)
		(layer "B.Cu")
		(net "FM_PCH_SLP_S4_N")
	)
	(segment
		(start 327.604628 -39.188898)
		(end 327.281286 -38.40734)
		(width 0.12954)
		(layer "B.Cu")
		(net "FM_PCH_SLP_S4_N")
	)
	(segment
		(start 327.963276 -40.096694)
		(end 327.604628 -39.738046)
		(width 0.12954)
		(layer "B.Cu")
		(net "FM_PCH_SLP_S4_N")
	)
	(segment
		(start 326.174862 -37.300916)
		(end 326.174862 -36.521136)
		(width 0.12954)
		(layer "B.Cu")
		(net "FM_PCH_SLP_S4_N")
	)
	(segment
		(start 322.312284 -29.473398)
		(end 322.74002 -29.473398)
		(width 0.12954)
		(layer "B.Cu")
		(net "FM_PCH_SLP_S4_N")
	)
	(segment
		(start 321.130676 -30.655006)
		(end 321.799204 -29.986478)
		(width 0.12954)
		(layer "B.Cu")
		(net "FM_PCH_SLP_S4_N")
	)
	(segment
		(start 322.938902 -33.688528)
		(end 321.130676 -31.880302)
		(width 0.12954)
		(layer "B.Cu")
		(net "FM_PCH_SLP_S4_N")
	)
	(segment
		(start 322.938902 -34.082228)
		(end 322.938902 -33.688528)
		(width 0.12954)
		(layer "B.Cu")
		(net "FM_PCH_SLP_S4_N")
	)
	(segment
		(start 329.233022 -41.392348)
		(end 328.868024 -41.02735)
		(width 0.0889)
		(layer "B.Cu")
		(net "FM_PCH_SLP_S4_N")
	)
	(segment
		(start 328.291444 -41.02735)
		(end 328.052176 -40.788082)
		(width 0.0889)
		(layer "B.Cu")
		(net "FM_PCH_SLP_S4_N")
	)
	(segment
		(start 330.671424 -42.14495)
		(end 330.426822 -41.900348)
		(width 0.0889)
		(layer "B.Cu")
		(net "FM_PCH_SLP_S4_N")
	)
	(segment
		(start 324.19163 -28.021788)
		(end 324.19163 -26.08707)
		(width 0.12954)
		(layer "B.Cu")
		(net "FM_PCH_SLP_S4_N")
	)
	(segment
		(start 327.963276 -40.699182)
		(end 327.963276 -40.096694)
		(width 0.12954)
		(layer "B.Cu")
		(net "FM_PCH_SLP_S4_N")
	)
	(segment
		(start 327.604628 -39.738046)
		(end 327.604628 -39.188898)
		(width 0.12954)
		(layer "B.Cu")
		(net "FM_PCH_SLP_S4_N")
	)
	(segment
		(start 330.071222 -41.900348)
		(end 329.563222 -41.392348)
		(width 0.0889)
		(layer "B.Cu")
		(net "FM_PCH_SLP_S4_N")
	)
	(segment
		(start 324.066662 -35.209988)
		(end 322.938902 -34.082228)
		(width 0.12954)
		(layer "B.Cu")
		(net "FM_PCH_SLP_S4_N")
	)
	(segment
		(start 321.799204 -29.986478)
		(end 322.312284 -29.473398)
		(width 0.12954)
		(layer "B.Cu")
		(net "FM_PCH_SLP_S4_N")
	)
	(segment
		(start 331.329284 -44.282106)
		(end 330.836016 -44.282106)
		(width 0.0889)
		(layer "B.Cu")
		(net "FM_PCH_SLP_S4_N")
	)
	(segment
		(start 324.863714 -35.209988)
		(end 324.066662 -35.209988)
		(width 0.12954)
		(layer "B.Cu")
		(net "FM_PCH_SLP_S4_N")
	)
	(segment
		(start 328.052176 -40.788082)
		(end 327.963276 -40.699182)
		(width 0.12954)
		(layer "B.Cu")
		(net "FM_PCH_SLP_S4_N")
	)
	(segment
		(start 326.174862 -36.521136)
		(end 324.863714 -35.209988)
		(width 0.12954)
		(layer "B.Cu")
		(net "FM_PCH_SLP_S4_N")
	)
	(segment
		(start 330.426822 -41.900348)
		(end 330.071222 -41.900348)
		(width 0.0889)
		(layer "B.Cu")
		(net "FM_PCH_SLP_S4_N")
	)
	(segment
		(start 330.836016 -44.282106)
		(end 330.671424 -44.117514)
		(width 0.0889)
		(layer "B.Cu")
		(net "FM_PCH_SLP_S4_N")
	)
	(segment
		(start 330.671424 -44.117514)
		(end 330.671424 -42.14495)
		(width 0.0889)
		(layer "B.Cu")
		(net "FM_PCH_SLP_S4_N")
	)
	(segment
		(start 321.130676 -31.880302)
		(end 321.130676 -30.655006)
		(width 0.12954)
		(layer "B.Cu")
		(net "FM_PCH_SLP_S4_N")
	)
	(segment
		(start 331.738224 -44.691046)
		(end 331.329284 -44.282106)
		(width 0.0889)
		(layer "B.Cu")
		(net "FM_PCH_SLP_S4_N")
	)
	(segment
		(start 328.868024 -41.02735)
		(end 328.291444 -41.02735)
		(width 0.0889)
		(layer "B.Cu")
		(net "FM_PCH_SLP_S4_N")
	)
	(segment
		(start 329.563222 -41.392348)
		(end 329.233022 -41.392348)
		(width 0.0889)
		(layer "B.Cu")
		(net "FM_PCH_SLP_S4_N")
	)
	(segment
		(start 322.74002 -29.473398)
		(end 324.19163 -28.021788)
		(width 0.12954)
		(layer "B.Cu")
		(net "FM_PCH_SLP_S4_N")
	)
	(segment
		(start 329.44054 -44.2214)
		(end 329.438762 -44.221146)
		(width 0.127)
		(layer "In6.Cu")
		(net "FM_PCH_SLP_S4_N")
	)
	(segment
		(start 305.44008 -38.293548)
		(end 297.237658 -38.293548)
		(width 0.127)
		(layer "In6.Cu")
		(net "FM_PCH_SLP_S4_N")
	)
	(segment
		(start 314.670694 -43.875198)
		(end 313.967368 -44.578524)
		(width 0.127)
		(layer "In6.Cu")
		(net "FM_PCH_SLP_S4_N")
	)
	(segment
		(start 326.71893 -43.875198)
		(end 314.670694 -43.875198)
		(width 0.127)
		(layer "In6.Cu")
		(net "FM_PCH_SLP_S4_N")
	)
	(segment
		(start 309.204106 -42.488866)
		(end 309.204106 -42.057574)
		(width 0.127)
		(layer "In6.Cu")
		(net "FM_PCH_SLP_S4_N")
	)
	(segment
		(start 313.967368 -44.578524)
		(end 311.293764 -44.578524)
		(width 0.127)
		(layer "In6.Cu")
		(net "FM_PCH_SLP_S4_N")
	)
	(segment
		(start 332.693518 -44.691046)
		(end 331.88148 -44.691046)
		(width 0.127)
		(layer "In6.Cu")
		(net "FM_PCH_SLP_S4_N")
	)
	(segment
		(start 330.65974 -44.456096)
		(end 330.658978 -44.457366)
		(width 0.127)
		(layer "In6.Cu")
		(net "FM_PCH_SLP_S4_N")
	)
	(segment
		(start 311.293764 -44.578524)
		(end 309.204106 -42.488866)
		(width 0.127)
		(layer "In6.Cu")
		(net "FM_PCH_SLP_S4_N")
	)
	(segment
		(start 330.253086 -44.691046)
		(end 330.25334 -44.691046)
		(width 0.127)
		(layer "In6.Cu")
		(net "FM_PCH_SLP_S4_N")
	)
	(segment
		(start 331.098906 -44.2214)
		(end 331.067156 -44.221146)
		(width 0.127)
		(layer "In6.Cu")
		(net "FM_PCH_SLP_S4_N")
	)
	(segment
		(start 330.67625 -44.427648)
		(end 330.65974 -44.456096)
		(width 0.127)
		(layer "In6.Cu")
		(net "FM_PCH_SLP_S4_N")
	)
	(segment
		(start 329.438762 -44.221146)
		(end 327.064878 -44.221146)
		(width 0.127)
		(layer "In6.Cu")
		(net "FM_PCH_SLP_S4_N")
	)
	(segment
		(start 286.63519 -48.896016)
		(end 286.63519 -50.332386)
		(width 0.127)
		(layer "In6.Cu")
		(net "FM_PCH_SLP_S4_N")
	)
	(segment
		(start 297.237658 -38.293548)
		(end 286.63519 -48.896016)
		(width 0.127)
		(layer "In6.Cu")
		(net "FM_PCH_SLP_S4_N")
	)
	(segment
		(start 327.064878 -44.221146)
		(end 326.71893 -43.875198)
		(width 0.127)
		(layer "In6.Cu")
		(net "FM_PCH_SLP_S4_N")
	)
	(segment
		(start 309.204106 -42.057574)
		(end 305.44008 -38.293548)
		(width 0.127)
		(layer "In6.Cu")
		(net "FM_PCH_SLP_S4_N")
	)
	(segment
		(start 331.88148 -44.691046)
		(end 331.846428 -44.690792)
		(width 0.127)
		(layer "In6.Cu")
		(net "FM_PCH_SLP_S4_N")
	)
	(segment
		(start 330.25334 -44.691046)
		(end 330.224892 -44.690792)
		(width 0.127)
		(layer "In6.Cu")
		(net "FM_PCH_SLP_S4_N")
	)
	(arc
		(start 330.658978 -44.457366)
		(mid 330.487342 -44.628602)
		(end 330.253086 -44.691046)
		(width 0.127)
		(layer "In6.Cu")
		(net "FM_PCH_SLP_S4_N")
	)
	(arc
		(start 329.845924 -44.456096)
		(mid 329.674634 -44.284524)
		(end 329.44054 -44.2214)
		(width 0.127)
		(layer "In6.Cu")
		(net "FM_PCH_SLP_S4_N")
	)
	(arc
		(start 331.473556 -44.456096)
		(mid 331.315505 -44.291988)
		(end 331.098906 -44.2214)
		(width 0.127)
		(layer "In6.Cu")
		(net "FM_PCH_SLP_S4_N")
	)
	(arc
		(start 330.224892 -44.690792)
		(mid 330.005821 -44.62119)
		(end 329.845924 -44.456096)
		(width 0.127)
		(layer "In6.Cu")
		(net "FM_PCH_SLP_S4_N")
	)
	(arc
		(start 331.067156 -44.221146)
		(mid 330.845897 -44.27555)
		(end 330.67625 -44.427648)
		(width 0.127)
		(layer "In6.Cu")
		(net "FM_PCH_SLP_S4_N")
	)
	(arc
		(start 331.846428 -44.690792)
		(mid 331.630821 -44.619759)
		(end 331.473556 -44.456096)
		(width 0.127)
		(layer "In6.Cu")
		(net "FM_PCH_SLP_S4_N")
	)
	(segment
		(start 275.08962 -61.204348)
		(end 281.37612 -54.917848)
		(width 0.127)
		(layer "In11.Cu")
		(net "FM_PCH_SLP_S4_N")
	)
	(segment
		(start 239.776 -67.069208)
		(end 243.17706 -63.668148)
		(width 0.127)
		(layer "In11.Cu")
		(net "FM_PCH_SLP_S4_N")
	)
	(segment
		(start 243.17706 -63.668148)
		(end 254.64262 -63.668148)
		(width 0.127)
		(layer "In11.Cu")
		(net "FM_PCH_SLP_S4_N")
	)
	(segment
		(start 109.70768 -102.943152)
		(end 110.758224 -101.892608)
		(width 0.127)
		(layer "In11.Cu")
		(net "FM_PCH_SLP_S4_N")
	)
	(segment
		(start 219.526358 -82.931762)
		(end 235.388912 -67.069208)
		(width 0.127)
		(layer "In11.Cu")
		(net "FM_PCH_SLP_S4_N")
	)
	(segment
		(start 284.224984 -54.917848)
		(end 286.63519 -52.507642)
		(width 0.127)
		(layer "In11.Cu")
		(net "FM_PCH_SLP_S4_N")
	)
	(segment
		(start 147.60448 -89.197688)
		(end 147.60448 -88.283288)
		(width 0.127)
		(layer "In11.Cu")
		(net "FM_PCH_SLP_S4_N")
	)
	(segment
		(start 281.37612 -54.917848)
		(end 284.224984 -54.917848)
		(width 0.127)
		(layer "In11.Cu")
		(net "FM_PCH_SLP_S4_N")
	)
	(segment
		(start 150.93442 -86.172548)
		(end 154.175206 -82.931762)
		(width 0.127)
		(layer "In11.Cu")
		(net "FM_PCH_SLP_S4_N")
	)
	(segment
		(start 134.90956 -101.892608)
		(end 147.60448 -89.197688)
		(width 0.127)
		(layer "In11.Cu")
		(net "FM_PCH_SLP_S4_N")
	)
	(segment
		(start 147.60448 -88.283288)
		(end 149.71522 -86.172548)
		(width 0.127)
		(layer "In11.Cu")
		(net "FM_PCH_SLP_S4_N")
	)
	(segment
		(start 110.758224 -101.892608)
		(end 134.90956 -101.892608)
		(width 0.127)
		(layer "In11.Cu")
		(net "FM_PCH_SLP_S4_N")
	)
	(segment
		(start 286.63519 -52.507642)
		(end 286.63519 -50.332386)
		(width 0.127)
		(layer "In11.Cu")
		(net "FM_PCH_SLP_S4_N")
	)
	(segment
		(start 257.10642 -61.204348)
		(end 275.08962 -61.204348)
		(width 0.127)
		(layer "In11.Cu")
		(net "FM_PCH_SLP_S4_N")
	)
	(segment
		(start 154.175206 -82.931762)
		(end 219.526358 -82.931762)
		(width 0.127)
		(layer "In11.Cu")
		(net "FM_PCH_SLP_S4_N")
	)
	(segment
		(start 254.64262 -63.668148)
		(end 257.10642 -61.204348)
		(width 0.127)
		(layer "In11.Cu")
		(net "FM_PCH_SLP_S4_N")
	)
	(segment
		(start 149.71522 -86.172548)
		(end 150.93442 -86.172548)
		(width 0.127)
		(layer "In11.Cu")
		(net "FM_PCH_SLP_S4_N")
	)
	(segment
		(start 235.388912 -67.069208)
		(end 239.776 -67.069208)
		(width 0.127)
		(layer "In11.Cu")
		(net "FM_PCH_SLP_S4_N")
	)
	(segment
		(start 329.980036 -43.751246)
		(end 329.439778 -43.751246)
		(width 0.12954)
		(layer "F.Cu")
		(net "FM_PCH_SLP_S3_N")
	)
	(segment
		(start 99.282504 -92.87256)
		(end 99.99853 -92.87256)
		(width 0.12954)
		(layer "F.Cu")
		(net "FM_PCH_SLP_S3_N")
	)
	(via
		(at 285.713932 -50.116486)
		(size 0.762)
		(drill 0.254)
		(layers "F.Cu" "B.Cu")
		(net "FM_PCH_SLP_S3_N")
	)
	(via
		(at 329.439778 -43.751246)
		(size 0.4572)
		(drill 0.2032)
		(layers "F.Cu" "B.Cu")
		(net "FM_PCH_SLP_S3_N")
	)
	(via
		(at 322.383912 -37.362638)
		(size 0.6604)
		(drill 0.3302)
		(layers "F.Cu" "B.Cu")
		(net "FM_PCH_SLP_S3_N")
	)
	(via
		(at 99.282504 -92.87256)
		(size 0.508)
		(drill 0.254)
		(layers "F.Cu" "B.Cu")
		(net "FM_PCH_SLP_S3_N")
	)
	(segment
		(start 325.67245 -41.869868)
		(end 325.372222 -41.144952)
		(width 0.12954)
		(layer "B.Cu")
		(net "FM_PCH_SLP_S3_N")
	)
	(segment
		(start 327.42251 -43.619928)
		(end 325.67245 -41.869868)
		(width 0.12954)
		(layer "B.Cu")
		(net "FM_PCH_SLP_S3_N")
	)
	(segment
		(start 329.156314 -43.751246)
		(end 329.083416 -43.678348)
		(width 0.0889)
		(layer "B.Cu")
		(net "FM_PCH_SLP_S3_N")
	)
	(segment
		(start 328.265536 -43.678348)
		(end 328.207116 -43.619928)
		(width 0.0889)
		(layer "B.Cu")
		(net "FM_PCH_SLP_S3_N")
	)
	(segment
		(start 322.839334 -37.81806)
		(end 322.383912 -37.362638)
		(width 0.12954)
		(layer "B.Cu")
		(net "FM_PCH_SLP_S3_N")
	)
	(segment
		(start 325.372222 -41.144952)
		(end 324.742556 -40.515286)
		(width 0.12954)
		(layer "B.Cu")
		(net "FM_PCH_SLP_S3_N")
	)
	(segment
		(start 322.383912 -37.362638)
		(end 321.489578 -36.468304)
		(width 0.12954)
		(layer "B.Cu")
		(net "FM_PCH_SLP_S3_N")
	)
	(segment
		(start 324.742556 -40.515286)
		(end 324.742556 -39.870634)
		(width 0.12954)
		(layer "B.Cu")
		(net "FM_PCH_SLP_S3_N")
	)
	(segment
		(start 329.083416 -43.678348)
		(end 328.265536 -43.678348)
		(width 0.0889)
		(layer "B.Cu")
		(net "FM_PCH_SLP_S3_N")
	)
	(segment
		(start 324.742556 -39.870634)
		(end 322.839334 -37.967412)
		(width 0.12954)
		(layer "B.Cu")
		(net "FM_PCH_SLP_S3_N")
	)
	(segment
		(start 329.439778 -43.751246)
		(end 329.156314 -43.751246)
		(width 0.0889)
		(layer "B.Cu")
		(net "FM_PCH_SLP_S3_N")
	)
	(segment
		(start 328.207116 -43.619928)
		(end 327.935336 -43.619928)
		(width 0.0889)
		(layer "B.Cu")
		(net "FM_PCH_SLP_S3_N")
	)
	(segment
		(start 322.839334 -37.967412)
		(end 322.839334 -37.81806)
		(width 0.12954)
		(layer "B.Cu")
		(net "FM_PCH_SLP_S3_N")
	)
	(segment
		(start 327.935336 -43.619928)
		(end 327.42251 -43.619928)
		(width 0.12954)
		(layer "B.Cu")
		(net "FM_PCH_SLP_S3_N")
	)
	(segment
		(start 309.847234 -42.089832)
		(end 305.61915 -37.861748)
		(width 0.127)
		(layer "In6.Cu")
		(net "FM_PCH_SLP_S3_N")
	)
	(segment
		(start 329.439778 -43.751246)
		(end 327.458578 -43.751246)
		(width 0.127)
		(layer "In6.Cu")
		(net "FM_PCH_SLP_S3_N")
	)
	(segment
		(start 313.286394 -42.089832)
		(end 309.847234 -42.089832)
		(width 0.127)
		(layer "In6.Cu")
		(net "FM_PCH_SLP_S3_N")
	)
	(segment
		(start 314.619894 -43.423332)
		(end 313.286394 -42.089832)
		(width 0.127)
		(layer "In6.Cu")
		(net "FM_PCH_SLP_S3_N")
	)
	(segment
		(start 327.458578 -43.751246)
		(end 327.130664 -43.423332)
		(width 0.127)
		(layer "In6.Cu")
		(net "FM_PCH_SLP_S3_N")
	)
	(segment
		(start 305.61915 -37.861748)
		(end 297.058588 -37.861748)
		(width 0.127)
		(layer "In6.Cu")
		(net "FM_PCH_SLP_S3_N")
	)
	(segment
		(start 297.058588 -37.861748)
		(end 285.713932 -49.206404)
		(width 0.127)
		(layer "In6.Cu")
		(net "FM_PCH_SLP_S3_N")
	)
	(segment
		(start 285.713932 -49.206404)
		(end 285.713932 -50.116486)
		(width 0.127)
		(layer "In6.Cu")
		(net "FM_PCH_SLP_S3_N")
	)
	(segment
		(start 327.130664 -43.423332)
		(end 314.619894 -43.423332)
		(width 0.127)
		(layer "In6.Cu")
		(net "FM_PCH_SLP_S3_N")
	)
	(segment
		(start 142.00124 -92.649548)
		(end 138.19886 -96.451928)
		(width 0.127)
		(layer "In11.Cu")
		(net "FM_PCH_SLP_S3_N")
	)
	(segment
		(start 150.57628 -85.308948)
		(end 149.35708 -85.308948)
		(width 0.127)
		(layer "In11.Cu")
		(net "FM_PCH_SLP_S3_N")
	)
	(segment
		(start 284.955742 -50.116486)
		(end 274.73148 -60.340748)
		(width 0.127)
		(layer "In11.Cu")
		(net "FM_PCH_SLP_S3_N")
	)
	(segment
		(start 146.74088 -87.925148)
		(end 146.74088 -88.839548)
		(width 0.127)
		(layer "In11.Cu")
		(net "FM_PCH_SLP_S3_N")
	)
	(segment
		(start 149.35708 -85.308948)
		(end 146.74088 -87.925148)
		(width 0.127)
		(layer "In11.Cu")
		(net "FM_PCH_SLP_S3_N")
	)
	(segment
		(start 254.28448 -62.804548)
		(end 242.81892 -62.804548)
		(width 0.127)
		(layer "In11.Cu")
		(net "FM_PCH_SLP_S3_N")
	)
	(segment
		(start 138.19886 -96.451928)
		(end 129.2733 -96.451928)
		(width 0.127)
		(layer "In11.Cu")
		(net "FM_PCH_SLP_S3_N")
	)
	(segment
		(start 233.780076 -66.205608)
		(end 217.917522 -82.068162)
		(width 0.127)
		(layer "In11.Cu")
		(net "FM_PCH_SLP_S3_N")
	)
	(segment
		(start 242.81892 -62.804548)
		(end 239.41786 -66.205608)
		(width 0.127)
		(layer "In11.Cu")
		(net "FM_PCH_SLP_S3_N")
	)
	(segment
		(start 100.398072 -92.87256)
		(end 99.282504 -92.87256)
		(width 0.127)
		(layer "In11.Cu")
		(net "FM_PCH_SLP_S3_N")
	)
	(segment
		(start 142.93088 -92.649548)
		(end 142.00124 -92.649548)
		(width 0.127)
		(layer "In11.Cu")
		(net "FM_PCH_SLP_S3_N")
	)
	(segment
		(start 116.95176 -98.626168)
		(end 114.05108 -95.725488)
		(width 0.127)
		(layer "In11.Cu")
		(net "FM_PCH_SLP_S3_N")
	)
	(segment
		(start 274.73148 -60.340748)
		(end 256.74828 -60.340748)
		(width 0.127)
		(layer "In11.Cu")
		(net "FM_PCH_SLP_S3_N")
	)
	(segment
		(start 127.09906 -98.626168)
		(end 116.95176 -98.626168)
		(width 0.127)
		(layer "In11.Cu")
		(net "FM_PCH_SLP_S3_N")
	)
	(segment
		(start 114.05108 -95.725488)
		(end 111.99114 -95.725488)
		(width 0.127)
		(layer "In11.Cu")
		(net "FM_PCH_SLP_S3_N")
	)
	(segment
		(start 129.2733 -96.451928)
		(end 127.09906 -98.626168)
		(width 0.127)
		(layer "In11.Cu")
		(net "FM_PCH_SLP_S3_N")
	)
	(segment
		(start 239.41786 -66.205608)
		(end 233.780076 -66.205608)
		(width 0.127)
		(layer "In11.Cu")
		(net "FM_PCH_SLP_S3_N")
	)
	(segment
		(start 111.99114 -95.725488)
		(end 110.73384 -94.468188)
		(width 0.127)
		(layer "In11.Cu")
		(net "FM_PCH_SLP_S3_N")
	)
	(segment
		(start 101.9937 -94.468188)
		(end 100.398072 -92.87256)
		(width 0.127)
		(layer "In11.Cu")
		(net "FM_PCH_SLP_S3_N")
	)
	(segment
		(start 285.713932 -50.116486)
		(end 284.955742 -50.116486)
		(width 0.127)
		(layer "In11.Cu")
		(net "FM_PCH_SLP_S3_N")
	)
	(segment
		(start 217.917522 -82.068162)
		(end 153.817066 -82.068162)
		(width 0.127)
		(layer "In11.Cu")
		(net "FM_PCH_SLP_S3_N")
	)
	(segment
		(start 256.74828 -60.340748)
		(end 254.28448 -62.804548)
		(width 0.127)
		(layer "In11.Cu")
		(net "FM_PCH_SLP_S3_N")
	)
	(segment
		(start 110.73384 -94.468188)
		(end 101.9937 -94.468188)
		(width 0.127)
		(layer "In11.Cu")
		(net "FM_PCH_SLP_S3_N")
	)
	(segment
		(start 153.817066 -82.068162)
		(end 150.57628 -85.308948)
		(width 0.127)
		(layer "In11.Cu")
		(net "FM_PCH_SLP_S3_N")
	)
	(segment
		(start 146.74088 -88.839548)
		(end 142.93088 -92.649548)
		(width 0.127)
		(layer "In11.Cu")
		(net "FM_PCH_SLP_S3_N")
	)
	(segment
		(start 330.79436 -42.341546)
		(end 330.253848 -42.341546)
		(width 0.12954)
		(layer "F.Cu")
		(net "FM_PCH_SKIP_RTC_CLOCK")
	)
	(via
		(at 330.253848 -42.341546)
		(size 0.4572)
		(drill 0.2032)
		(layers "F.Cu" "B.Cu")
		(net "FM_PCH_SKIP_RTC_CLOCK")
	)
	(via
		(at 321.821556 -28.451048)
		(size 0.6604)
		(drill 0.3302)
		(layers "F.Cu" "B.Cu")
		(net "FM_PCH_SKIP_RTC_CLOCK")
	)
	(segment
		(start 327.079356 -39.375842)
		(end 326.931782 -39.01948)
		(width 0.12954)
		(layer "B.Cu")
		(net "FM_PCH_SKIP_RTC_CLOCK")
	)
	(segment
		(start 330.253848 -42.341546)
		(end 329.9714 -42.341546)
		(width 0.0889)
		(layer "B.Cu")
		(net "FM_PCH_SKIP_RTC_CLOCK")
	)
	(segment
		(start 328.314304 -41.776396)
		(end 327.970896 -41.432988)
		(width 0.0889)
		(layer "B.Cu")
		(net "FM_PCH_SKIP_RTC_CLOCK")
	)
	(segment
		(start 326.931782 -39.01948)
		(end 326.546464 -38.634162)
		(width 0.12954)
		(layer "B.Cu")
		(net "FM_PCH_SKIP_RTC_CLOCK")
	)
	(segment
		(start 329.607164 -42.246042)
		(end 329.440032 -42.246296)
		(width 0.0889)
		(layer "B.Cu")
		(net "FM_PCH_SKIP_RTC_CLOCK")
	)
	(segment
		(start 327.079356 -40.099488)
		(end 327.079356 -39.375842)
		(width 0.12954)
		(layer "B.Cu")
		(net "FM_PCH_SKIP_RTC_CLOCK")
	)
	(segment
		(start 321.747642 -27.584908)
		(end 321.747642 -27.11069)
		(width 0.12954)
		(layer "B.Cu")
		(net "FM_PCH_SKIP_RTC_CLOCK")
	)
	(segment
		(start 329.875896 -42.246042)
		(end 329.607164 -42.246042)
		(width 0.0889)
		(layer "B.Cu")
		(net "FM_PCH_SKIP_RTC_CLOCK")
	)
	(segment
		(start 329.1205 -42.067988)
		(end 329.11542 -42.058844)
		(width 0.0889)
		(layer "B.Cu")
		(net "FM_PCH_SKIP_RTC_CLOCK")
	)
	(segment
		(start 321.747642 -27.11069)
		(end 320.645282 -27.11069)
		(width 0.12954)
		(layer "B.Cu")
		(net "FM_PCH_SKIP_RTC_CLOCK")
	)
	(segment
		(start 321.821556 -27.658822)
		(end 321.747642 -27.584908)
		(width 0.12954)
		(layer "B.Cu")
		(net "FM_PCH_SKIP_RTC_CLOCK")
	)
	(segment
		(start 321.821556 -29.219398)
		(end 321.821556 -28.451048)
		(width 0.12954)
		(layer "B.Cu")
		(net "FM_PCH_SKIP_RTC_CLOCK")
	)
	(segment
		(start 327.432416 -40.894508)
		(end 327.432416 -40.452548)
		(width 0.12954)
		(layer "B.Cu")
		(net "FM_PCH_SKIP_RTC_CLOCK")
	)
	(segment
		(start 327.432416 -40.452548)
		(end 327.079356 -40.099488)
		(width 0.12954)
		(layer "B.Cu")
		(net "FM_PCH_SKIP_RTC_CLOCK")
	)
	(segment
		(start 320.601594 -30.43936)
		(end 321.821556 -29.219398)
		(width 0.12954)
		(layer "B.Cu")
		(net "FM_PCH_SKIP_RTC_CLOCK")
	)
	(segment
		(start 321.087496 -32.583628)
		(end 320.601594 -32.097726)
		(width 0.12954)
		(layer "B.Cu")
		(net "FM_PCH_SKIP_RTC_CLOCK")
	)
	(segment
		(start 321.087496 -33.200086)
		(end 321.087496 -32.583628)
		(width 0.12954)
		(layer "B.Cu")
		(net "FM_PCH_SKIP_RTC_CLOCK")
	)
	(segment
		(start 328.64425 -41.776396)
		(end 328.314304 -41.776396)
		(width 0.0889)
		(layer "B.Cu")
		(net "FM_PCH_SKIP_RTC_CLOCK")
	)
	(segment
		(start 326.546464 -38.634162)
		(end 326.15632 -38.472618)
		(width 0.12954)
		(layer "B.Cu")
		(net "FM_PCH_SKIP_RTC_CLOCK")
	)
	(segment
		(start 326.15632 -38.472618)
		(end 325.989696 -38.472618)
		(width 0.12954)
		(layer "B.Cu")
		(net "FM_PCH_SKIP_RTC_CLOCK")
	)
	(segment
		(start 321.821556 -28.451048)
		(end 321.821556 -27.658822)
		(width 0.12954)
		(layer "B.Cu")
		(net "FM_PCH_SKIP_RTC_CLOCK")
	)
	(segment
		(start 329.9714 -42.341546)
		(end 329.875896 -42.246042)
		(width 0.0889)
		(layer "B.Cu")
		(net "FM_PCH_SKIP_RTC_CLOCK")
	)
	(segment
		(start 327.970896 -41.432988)
		(end 327.432416 -40.894508)
		(width 0.12954)
		(layer "B.Cu")
		(net "FM_PCH_SKIP_RTC_CLOCK")
	)
	(segment
		(start 320.601594 -32.097726)
		(end 320.601594 -30.43936)
		(width 0.12954)
		(layer "B.Cu")
		(net "FM_PCH_SKIP_RTC_CLOCK")
	)
	(segment
		(start 325.420736 -37.533326)
		(end 321.087496 -33.200086)
		(width 0.12954)
		(layer "B.Cu")
		(net "FM_PCH_SKIP_RTC_CLOCK")
	)
	(segment
		(start 325.420736 -37.903658)
		(end 325.420736 -37.533326)
		(width 0.12954)
		(layer "B.Cu")
		(net "FM_PCH_SKIP_RTC_CLOCK")
	)
	(segment
		(start 325.989696 -38.472618)
		(end 325.420736 -37.903658)
		(width 0.12954)
		(layer "B.Cu")
		(net "FM_PCH_SKIP_RTC_CLOCK")
	)
	(arc
		(start 329.440032 -42.246296)
		(mid 329.256998 -42.198826)
		(end 329.1205 -42.067988)
		(width 0.0889)
		(layer "B.Cu")
		(net "FM_PCH_SKIP_RTC_CLOCK")
	)
	(arc
		(start 329.11542 -42.058844)
		(mid 328.916439 -41.856558)
		(end 328.64425 -41.776396)
		(width 0.0889)
		(layer "B.Cu")
		(net "FM_PCH_SKIP_RTC_CLOCK")
	)
	(segment
		(start 331.397102 -38.51783)
		(end 331.22489 -38.345618)
		(width 0.0889)
		(layer "F.Cu")
		(net "FM_PCH_SATA_RAID_KEY")
	)
	(segment
		(start 331.05725 -38.151562)
		(end 331.027024 -38.090602)
		(width 0.0889)
		(layer "F.Cu")
		(net "FM_PCH_SATA_RAID_KEY")
	)
	(segment
		(start 331.176122 -37.351462)
		(end 331.174852 -37.350192)
		(width 0.0889)
		(layer "F.Cu")
		(net "FM_PCH_SATA_RAID_KEY")
	)
	(segment
		(start 326.40524 -21.679408)
		(end 326.40524 -23.531068)
		(width 0.12954)
		(layer "F.Cu")
		(net "FM_PCH_SATA_RAID_KEY")
	)
	(segment
		(start 326.49414 -25.494488)
		(end 326.8345 -25.834848)
		(width 0.12954)
		(layer "F.Cu")
		(net "FM_PCH_SATA_RAID_KEY")
	)
	(segment
		(start 331.22489 -38.345618)
		(end 331.05725 -38.151562)
		(width 0.0889)
		(layer "F.Cu")
		(net "FM_PCH_SATA_RAID_KEY")
	)
	(segment
		(start 329.106022 -31.648908)
		(end 328.344022 -30.886908)
		(width 0.12954)
		(layer "F.Cu")
		(net "FM_PCH_SATA_RAID_KEY")
	)
	(segment
		(start 331.174852 -35.523678)
		(end 330.367894 -34.71672)
		(width 0.0889)
		(layer "F.Cu")
		(net "FM_PCH_SATA_RAID_KEY")
	)
	(segment
		(start 331.174852 -37.350192)
		(end 331.174852 -35.523678)
		(width 0.0889)
		(layer "F.Cu")
		(net "FM_PCH_SATA_RAID_KEY")
	)
	(segment
		(start 328.242422 -30.749748)
		(end 326.977756 -28.385262)
		(width 0.12954)
		(layer "F.Cu")
		(net "FM_PCH_SATA_RAID_KEY")
	)
	(segment
		(start 326.977756 -25.978104)
		(end 326.8345 -25.834848)
		(width 0.12954)
		(layer "F.Cu")
		(net "FM_PCH_SATA_RAID_KEY")
	)
	(segment
		(start 331.027024 -38.090602)
		(end 331.027024 -37.992304)
		(width 0.0889)
		(layer "F.Cu")
		(net "FM_PCH_SATA_RAID_KEY")
	)
	(segment
		(start 330.367894 -33.99282)
		(end 329.476862 -33.101788)
		(width 0.0889)
		(layer "F.Cu")
		(net "FM_PCH_SATA_RAID_KEY")
	)
	(segment
		(start 331.397102 -38.880288)
		(end 331.397102 -38.51783)
		(width 0.0889)
		(layer "F.Cu")
		(net "FM_PCH_SATA_RAID_KEY")
	)
	(segment
		(start 330.367894 -34.71672)
		(end 330.367894 -33.99282)
		(width 0.0889)
		(layer "F.Cu")
		(net "FM_PCH_SATA_RAID_KEY")
	)
	(segment
		(start 325.605902 -20.948396)
		(end 326.647302 -20.948396)
		(width 0.12954)
		(layer "F.Cu")
		(net "FM_PCH_SATA_RAID_KEY")
	)
	(segment
		(start 326.40524 -23.531068)
		(end 326.49414 -23.619968)
		(width 0.12954)
		(layer "F.Cu")
		(net "FM_PCH_SATA_RAID_KEY")
	)
	(segment
		(start 331.176122 -37.768276)
		(end 331.176122 -37.351462)
		(width 0.0889)
		(layer "F.Cu")
		(net "FM_PCH_SATA_RAID_KEY")
	)
	(segment
		(start 331.027024 -37.992304)
		(end 331.176122 -37.768276)
		(width 0.0889)
		(layer "F.Cu")
		(net "FM_PCH_SATA_RAID_KEY")
	)
	(segment
		(start 329.476862 -33.101788)
		(end 329.476862 -32.595058)
		(width 0.0889)
		(layer "F.Cu")
		(net "FM_PCH_SATA_RAID_KEY")
	)
	(segment
		(start 326.49414 -23.619968)
		(end 326.49414 -25.494488)
		(width 0.12954)
		(layer "F.Cu")
		(net "FM_PCH_SATA_RAID_KEY")
	)
	(segment
		(start 328.344022 -30.886908)
		(end 328.344022 -30.851348)
		(width 0.12954)
		(layer "F.Cu")
		(net "FM_PCH_SATA_RAID_KEY")
	)
	(segment
		(start 326.977756 -28.385262)
		(end 326.977756 -25.978104)
		(width 0.12954)
		(layer "F.Cu")
		(net "FM_PCH_SATA_RAID_KEY")
	)
	(segment
		(start 329.476862 -32.595058)
		(end 329.106022 -32.224218)
		(width 0.0889)
		(layer "F.Cu")
		(net "FM_PCH_SATA_RAID_KEY")
	)
	(segment
		(start 326.647302 -20.948396)
		(end 326.647302 -21.437346)
		(width 0.12954)
		(layer "F.Cu")
		(net "FM_PCH_SATA_RAID_KEY")
	)
	(segment
		(start 329.106022 -32.224218)
		(end 329.106022 -31.648908)
		(width 0.12954)
		(layer "F.Cu")
		(net "FM_PCH_SATA_RAID_KEY")
	)
	(segment
		(start 328.344022 -30.851348)
		(end 328.242422 -30.749748)
		(width 0.12954)
		(layer "F.Cu")
		(net "FM_PCH_SATA_RAID_KEY")
	)
	(segment
		(start 326.647302 -21.437346)
		(end 326.40524 -21.679408)
		(width 0.12954)
		(layer "F.Cu")
		(net "FM_PCH_SATA_RAID_KEY")
	)
	(via
		(at 326.8345 -25.834848)
		(size 0.762)
		(drill 0.381)
		(layers "F.Cu" "B.Cu")
		(net "FM_PCH_SATA_RAID_KEY")
	)
	(segment
		(start 325.343012 -57.264046)
		(end 325.343012 -57.485788)
		(width 0.0889)
		(layer "F.Cu")
		(net "FM_PCH_RING_OSC_BYPASS_MGPIO_TE")
	)
	(segment
		(start 326.9996 -56.454294)
		(end 326.468232 -56.454294)
		(width 0.0889)
		(layer "F.Cu")
		(net "FM_PCH_RING_OSC_BYPASS_MGPIO_TE")
	)
	(segment
		(start 320.069972 -62.385448)
		(end 318.77762 -62.385448)
		(width 0.12954)
		(layer "F.Cu")
		(net "FM_PCH_RING_OSC_BYPASS_MGPIO_TE")
	)
	(segment
		(start 321.714876 -61.554868)
		(end 320.900552 -61.554868)
		(width 0.12954)
		(layer "F.Cu")
		(net "FM_PCH_RING_OSC_BYPASS_MGPIO_TE")
	)
	(segment
		(start 320.590672 -61.864748)
		(end 320.069972 -62.385448)
		(width 0.12954)
		(layer "F.Cu")
		(net "FM_PCH_RING_OSC_BYPASS_MGPIO_TE")
	)
	(segment
		(start 325.66991 -56.937148)
		(end 325.343012 -57.264046)
		(width 0.0889)
		(layer "F.Cu")
		(net "FM_PCH_RING_OSC_BYPASS_MGPIO_TE")
	)
	(segment
		(start 325.343012 -57.485788)
		(end 325.343012 -57.926732)
		(width 0.12954)
		(layer "F.Cu")
		(net "FM_PCH_RING_OSC_BYPASS_MGPIO_TE")
	)
	(segment
		(start 325.985378 -56.937148)
		(end 325.66991 -56.937148)
		(width 0.0889)
		(layer "F.Cu")
		(net "FM_PCH_RING_OSC_BYPASS_MGPIO_TE")
	)
	(segment
		(start 326.468232 -56.454294)
		(end 325.985378 -56.937148)
		(width 0.0889)
		(layer "F.Cu")
		(net "FM_PCH_RING_OSC_BYPASS_MGPIO_TE")
	)
	(segment
		(start 326.999854 -56.45404)
		(end 326.9996 -56.454294)
		(width 0.0889)
		(layer "F.Cu")
		(net "FM_PCH_RING_OSC_BYPASS_MGPIO_TE")
	)
	(segment
		(start 325.343012 -57.926732)
		(end 321.714876 -61.554868)
		(width 0.12954)
		(layer "F.Cu")
		(net "FM_PCH_RING_OSC_BYPASS_MGPIO_TE")
	)
	(segment
		(start 320.900552 -61.554868)
		(end 320.590672 -61.864748)
		(width 0.12954)
		(layer "F.Cu")
		(net "FM_PCH_RING_OSC_BYPASS_MGPIO_TE")
	)
	(segment
		(start 318.77762 -62.385448)
		(end 318.5033 -62.659768)
		(width 0.12954)
		(layer "F.Cu")
		(net "FM_PCH_RING_OSC_BYPASS_MGPIO_TE")
	)
	(segment
		(start 318.5033 -62.037976)
		(end 317.796672 -61.331348)
		(width 0.12954)
		(layer "F.Cu")
		(net "FM_PCH_RING_OSC_BYPASS_MGPIO_TE")
	)
	(segment
		(start 318.5033 -62.659768)
		(end 318.5033 -62.037976)
		(width 0.12954)
		(layer "F.Cu")
		(net "FM_PCH_RING_OSC_BYPASS_MGPIO_TE")
	)
	(via
		(at 318.5033 -62.659768)
		(size 0.508)
		(drill 0.254)
		(layers "F.Cu" "B.Cu")
		(net "FM_PCH_RING_OSC_BYPASS_MGPIO_TE")
	)
	(segment
		(start 348.289118 -59.265312)
		(end 346.559378 -59.265312)
		(width 0.12954)
		(layer "F.Cu")
		(net "FM_PCH_PRSNT_N")
	)
	(segment
		(start 170.955716 -107.375452)
		(end 170.555666 -106.975402)
		(width 0.12954)
		(layer "F.Cu")
		(net "FM_PCH_PRSNT_N")
	)
	(segment
		(start 350.83369 -59.94908)
		(end 349.955358 -59.070748)
		(width 0.12954)
		(layer "F.Cu")
		(net "FM_PCH_PRSNT_N")
	)
	(segment
		(start 348.483682 -59.070748)
		(end 348.289118 -59.265312)
		(width 0.12954)
		(layer "F.Cu")
		(net "FM_PCH_PRSNT_N")
	)
	(segment
		(start 349.955358 -59.070748)
		(end 348.483682 -59.070748)
		(width 0.12954)
		(layer "F.Cu")
		(net "FM_PCH_PRSNT_N")
	)
	(via
		(at 350.83369 -59.94908)
		(size 0.508)
		(drill 0.254)
		(layers "F.Cu" "B.Cu")
		(net "FM_PCH_PRSNT_N")
	)
	(via
		(at 285.58744 -65.966848)
		(size 0.508)
		(drill 0.254)
		(layers "F.Cu" "B.Cu")
		(net "FM_PCH_PRSNT_N")
	)
	(via
		(at 170.555666 -106.975402)
		(size 0.4572)
		(drill 0.254)
		(layers "F.Cu" "B.Cu")
		(net "FM_PCH_PRSNT_N")
	)
	(segment
		(start 351.318322 -59.464448)
		(end 352.006916 -59.464448)
		(width 0.12954)
		(layer "B.Cu")
		(net "FM_PCH_PRSNT_N")
	)
	(segment
		(start 352.006916 -59.464448)
		(end 352.28022 -59.737752)
		(width 0.12954)
		(layer "B.Cu")
		(net "FM_PCH_PRSNT_N")
	)
	(segment
		(start 350.83369 -59.94908)
		(end 351.318322 -59.464448)
		(width 0.12954)
		(layer "B.Cu")
		(net "FM_PCH_PRSNT_N")
	)
	(segment
		(start 170.46448 -102.428548)
		(end 169.75328 -101.717348)
		(width 0.127)
		(layer "In13.Cu")
		(net "FM_PCH_PRSNT_N")
	)
	(segment
		(start 238.863378 -88.661494)
		(end 244.409722 -83.11515)
		(width 0.127)
		(layer "In13.Cu")
		(net "FM_PCH_PRSNT_N")
	)
	(segment
		(start 170.46448 -104.511348)
		(end 170.46448 -102.428548)
		(width 0.127)
		(layer "In13.Cu")
		(net "FM_PCH_PRSNT_N")
	)
	(segment
		(start 170.555666 -106.134154)
		(end 169.93108 -105.509568)
		(width 0.127)
		(layer "In13.Cu")
		(net "FM_PCH_PRSNT_N")
	)
	(segment
		(start 244.409722 -83.11515)
		(end 277.321518 -83.11515)
		(width 0.127)
		(layer "In13.Cu")
		(net "FM_PCH_PRSNT_N")
	)
	(segment
		(start 169.93108 -105.509568)
		(end 169.93108 -105.044748)
		(width 0.127)
		(layer "In13.Cu")
		(net "FM_PCH_PRSNT_N")
	)
	(segment
		(start 170.3832 -100.554028)
		(end 170.3832 -93.208348)
		(width 0.127)
		(layer "In13.Cu")
		(net "FM_PCH_PRSNT_N")
	)
	(segment
		(start 285.58744 -74.849228)
		(end 285.58744 -65.966848)
		(width 0.127)
		(layer "In13.Cu")
		(net "FM_PCH_PRSNT_N")
	)
	(segment
		(start 169.93108 -105.044748)
		(end 170.46448 -104.511348)
		(width 0.127)
		(layer "In13.Cu")
		(net "FM_PCH_PRSNT_N")
	)
	(segment
		(start 176.312322 -90.90787)
		(end 181.979824 -85.240368)
		(width 0.127)
		(layer "In13.Cu")
		(net "FM_PCH_PRSNT_N")
	)
	(segment
		(start 170.555666 -106.975402)
		(end 170.555666 -106.134154)
		(width 0.127)
		(layer "In13.Cu")
		(net "FM_PCH_PRSNT_N")
	)
	(segment
		(start 222.189802 -88.661494)
		(end 238.863378 -88.661494)
		(width 0.127)
		(layer "In13.Cu")
		(net "FM_PCH_PRSNT_N")
	)
	(segment
		(start 277.321518 -83.11515)
		(end 285.58744 -74.849228)
		(width 0.127)
		(layer "In13.Cu")
		(net "FM_PCH_PRSNT_N")
	)
	(segment
		(start 181.979824 -85.240368)
		(end 218.768676 -85.240368)
		(width 0.127)
		(layer "In13.Cu")
		(net "FM_PCH_PRSNT_N")
	)
	(segment
		(start 170.3832 -93.208348)
		(end 172.683678 -90.90787)
		(width 0.127)
		(layer "In13.Cu")
		(net "FM_PCH_PRSNT_N")
	)
	(segment
		(start 218.768676 -85.240368)
		(end 222.189802 -88.661494)
		(width 0.127)
		(layer "In13.Cu")
		(net "FM_PCH_PRSNT_N")
	)
	(segment
		(start 172.683678 -90.90787)
		(end 176.312322 -90.90787)
		(width 0.127)
		(layer "In13.Cu")
		(net "FM_PCH_PRSNT_N")
	)
	(segment
		(start 169.75328 -101.717348)
		(end 169.75328 -101.183948)
		(width 0.127)
		(layer "In13.Cu")
		(net "FM_PCH_PRSNT_N")
	)
	(segment
		(start 169.75328 -101.183948)
		(end 170.3832 -100.554028)
		(width 0.127)
		(layer "In13.Cu")
		(net "FM_PCH_PRSNT_N")
	)
	(segment
		(start 289.27806 -59.367928)
		(end 285.58744 -63.058548)
		(width 0.127)
		(layer "In15.Cu")
		(net "FM_PCH_PRSNT_N")
	)
	(segment
		(start 323.1642 -62.403228)
		(end 322.93052 -62.636908)
		(width 0.127)
		(layer "In15.Cu")
		(net "FM_PCH_PRSNT_N")
	)
	(segment
		(start 349.677482 -61.105288)
		(end 330.83246 -61.105288)
		(width 0.127)
		(layer "In15.Cu")
		(net "FM_PCH_PRSNT_N")
	)
	(segment
		(start 311.3151 -64.285368)
		(end 310.2356 -65.364868)
		(width 0.127)
		(layer "In15.Cu")
		(net "FM_PCH_PRSNT_N")
	)
	(segment
		(start 310.2356 -65.364868)
		(end 302.44288 -65.364868)
		(width 0.127)
		(layer "In15.Cu")
		(net "FM_PCH_PRSNT_N")
	)
	(segment
		(start 285.58744 -63.058548)
		(end 285.58744 -65.966848)
		(width 0.127)
		(layer "In15.Cu")
		(net "FM_PCH_PRSNT_N")
	)
	(segment
		(start 302.44288 -65.364868)
		(end 296.44594 -59.367928)
		(width 0.127)
		(layer "In15.Cu")
		(net "FM_PCH_PRSNT_N")
	)
	(segment
		(start 318.31788 -63.520828)
		(end 317.373 -62.575948)
		(width 0.127)
		(layer "In15.Cu")
		(net "FM_PCH_PRSNT_N")
	)
	(segment
		(start 330.83246 -61.105288)
		(end 329.53452 -62.403228)
		(width 0.127)
		(layer "In15.Cu")
		(net "FM_PCH_PRSNT_N")
	)
	(segment
		(start 296.44594 -59.367928)
		(end 289.27806 -59.367928)
		(width 0.127)
		(layer "In15.Cu")
		(net "FM_PCH_PRSNT_N")
	)
	(segment
		(start 319.62344 -63.520828)
		(end 318.31788 -63.520828)
		(width 0.127)
		(layer "In15.Cu")
		(net "FM_PCH_PRSNT_N")
	)
	(segment
		(start 350.83369 -59.94908)
		(end 349.677482 -61.105288)
		(width 0.127)
		(layer "In15.Cu")
		(net "FM_PCH_PRSNT_N")
	)
	(segment
		(start 322.93052 -62.636908)
		(end 320.50736 -62.636908)
		(width 0.127)
		(layer "In15.Cu")
		(net "FM_PCH_PRSNT_N")
	)
	(segment
		(start 329.53452 -62.403228)
		(end 323.1642 -62.403228)
		(width 0.127)
		(layer "In15.Cu")
		(net "FM_PCH_PRSNT_N")
	)
	(segment
		(start 317.373 -62.575948)
		(end 312.67146 -62.575948)
		(width 0.127)
		(layer "In15.Cu")
		(net "FM_PCH_PRSNT_N")
	)
	(segment
		(start 312.67146 -62.575948)
		(end 311.3151 -63.932308)
		(width 0.127)
		(layer "In15.Cu")
		(net "FM_PCH_PRSNT_N")
	)
	(segment
		(start 320.50736 -62.636908)
		(end 319.62344 -63.520828)
		(width 0.127)
		(layer "In15.Cu")
		(net "FM_PCH_PRSNT_N")
	)
	(segment
		(start 311.3151 -63.932308)
		(end 311.3151 -64.285368)
		(width 0.127)
		(layer "In15.Cu")
		(net "FM_PCH_PRSNT_N")
	)
	(segment
		(start 192.74028 -120.614948)
		(end 192.98031 -120.614948)
		(width 0.12954)
		(layer "F.Cu")
		(net "FM_PCH_PLD_GLB_RST_WARN_N")
	)
	(segment
		(start 189.72022 -118.659148)
		(end 190.55588 -118.659148)
		(width 0.12954)
		(layer "F.Cu")
		(net "FM_PCH_PLD_GLB_RST_WARN_N")
	)
	(segment
		(start 186.58205 -117.401848)
		(end 188.46292 -117.401848)
		(width 0.12954)
		(layer "F.Cu")
		(net "FM_PCH_PLD_GLB_RST_WARN_N")
	)
	(segment
		(start 190.78448 -118.659148)
		(end 192.74028 -120.614948)
		(width 0.12954)
		(layer "F.Cu")
		(net "FM_PCH_PLD_GLB_RST_WARN_N")
	)
	(segment
		(start 188.46292 -117.401848)
		(end 189.72022 -118.659148)
		(width 0.12954)
		(layer "F.Cu")
		(net "FM_PCH_PLD_GLB_RST_WARN_N")
	)
	(segment
		(start 186.155584 -116.975382)
		(end 186.58205 -117.401848)
		(width 0.12954)
		(layer "F.Cu")
		(net "FM_PCH_PLD_GLB_RST_WARN_N")
	)
	(segment
		(start 190.55588 -118.659148)
		(end 190.78448 -118.659148)
		(width 0.12954)
		(layer "F.Cu")
		(net "FM_PCH_PLD_GLB_RST_WARN_N")
	)
	(via
		(at 190.55588 -118.659148)
		(size 0.762)
		(drill 0.381)
		(layers "F.Cu" "B.Cu")
		(net "FM_PCH_PLD_GLB_RST_WARN_N")
	)
	(segment
		(start 384.109976 -79.126588)
		(end 384.109976 -77.594206)
		(width 0.12954)
		(layer "F.Cu")
		(net "FM_PCH_P1V8_AUX_EN_R")
	)
	(via
		(at 384.109976 -79.126588)
		(size 0.762)
		(drill 0.254)
		(layers "F.Cu" "B.Cu")
		(net "FM_PCH_P1V8_AUX_EN_R")
	)
	(segment
		(start 383.650998 -79.51978)
		(end 383.650998 -79.6925)
		(width 0.12954)
		(layer "B.Cu")
		(net "FM_PCH_P1V8_AUX_EN_R")
	)
	(segment
		(start 384.74015 -79.428848)
		(end 384.412236 -79.428848)
		(width 0.12954)
		(layer "B.Cu")
		(net "FM_PCH_P1V8_AUX_EN_R")
	)
	(segment
		(start 384.04419 -79.126588)
		(end 383.650998 -79.51978)
		(width 0.12954)
		(layer "B.Cu")
		(net "FM_PCH_P1V8_AUX_EN_R")
	)
	(segment
		(start 384.412236 -79.428848)
		(end 384.109976 -79.126588)
		(width 0.12954)
		(layer "B.Cu")
		(net "FM_PCH_P1V8_AUX_EN_R")
	)
	(segment
		(start 384.109976 -79.126588)
		(end 384.04419 -79.126588)
		(width 0.12954)
		(layer "B.Cu")
		(net "FM_PCH_P1V8_AUX_EN_R")
	)
	(segment
		(start 174.155608 -119.375428)
		(end 173.755558 -119.775478)
		(width 0.12954)
		(layer "F.Cu")
		(net "FM_PCH_P1V8_AUX_EN")
	)
	(segment
		(start 172.77588 -126.564898)
		(end 172.77588 -125.955298)
		(width 0.12954)
		(layer "F.Cu")
		(net "FM_PCH_P1V8_AUX_EN")
	)
	(via
		(at 312.60288 -96.611948)
		(size 0.508)
		(drill 0.254)
		(layers "F.Cu" "B.Cu")
		(net "FM_PCH_P1V8_AUX_EN")
	)
	(via
		(at 172.77588 -125.955298)
		(size 0.508)
		(drill 0.254)
		(layers "F.Cu" "B.Cu")
		(net "FM_PCH_P1V8_AUX_EN")
	)
	(via
		(at 173.755558 -119.775478)
		(size 0.4572)
		(drill 0.254)
		(layers "F.Cu" "B.Cu")
		(net "FM_PCH_P1V8_AUX_EN")
	)
	(segment
		(start 381.574548 -80.4926)
		(end 383.650998 -80.4926)
		(width 0.12954)
		(layer "B.Cu")
		(net "FM_PCH_P1V8_AUX_EN")
	)
	(segment
		(start 312.60288 -96.611948)
		(end 313.49188 -97.500948)
		(width 0.12954)
		(layer "B.Cu")
		(net "FM_PCH_P1V8_AUX_EN")
	)
	(segment
		(start 370.338096 -82.997548)
		(end 379.0696 -82.997548)
		(width 0.12954)
		(layer "B.Cu")
		(net "FM_PCH_P1V8_AUX_EN")
	)
	(segment
		(start 379.0696 -82.997548)
		(end 381.574548 -80.4926)
		(width 0.12954)
		(layer "B.Cu")
		(net "FM_PCH_P1V8_AUX_EN")
	)
	(segment
		(start 313.49188 -97.500948)
		(end 355.834696 -97.500948)
		(width 0.12954)
		(layer "B.Cu")
		(net "FM_PCH_P1V8_AUX_EN")
	)
	(segment
		(start 355.834696 -97.500948)
		(end 370.338096 -82.997548)
		(width 0.12954)
		(layer "B.Cu")
		(net "FM_PCH_P1V8_AUX_EN")
	)
	(segment
		(start 181.5846 -91.2622)
		(end 182.753 -92.4306)
		(width 0.127)
		(layer "In11.Cu")
		(net "FM_PCH_P1V8_AUX_EN")
	)
	(segment
		(start 184.4675 -94.5515)
		(end 184.852818 -94.5515)
		(width 0.127)
		(layer "In11.Cu")
		(net "FM_PCH_P1V8_AUX_EN")
	)
	(segment
		(start 238.22025 -102.827328)
		(end 244.42547 -109.032548)
		(width 0.127)
		(layer "In11.Cu")
		(net "FM_PCH_P1V8_AUX_EN")
	)
	(segment
		(start 173.755558 -119.775478)
		(end 174.1551 -120.17502)
		(width 0.127)
		(layer "In11.Cu")
		(net "FM_PCH_P1V8_AUX_EN")
	)
	(segment
		(start 171.9326 -92.329)
		(end 172.9994 -91.2622)
		(width 0.127)
		(layer "In11.Cu")
		(net "FM_PCH_P1V8_AUX_EN")
	)
	(segment
		(start 174.1551 -121.74982)
		(end 173.8503 -122.05462)
		(width 0.127)
		(layer "In11.Cu")
		(net "FM_PCH_P1V8_AUX_EN")
	)
	(segment
		(start 174.15764 -118.71452)
		(end 174.28972 -118.58244)
		(width 0.127)
		(layer "In11.Cu")
		(net "FM_PCH_P1V8_AUX_EN")
	)
	(segment
		(start 311.99328 -98.618548)
		(end 312.60288 -98.008948)
		(width 0.127)
		(layer "In11.Cu")
		(net "FM_PCH_P1V8_AUX_EN")
	)
	(segment
		(start 189.197488 -95.623888)
		(end 192.157858 -95.623888)
		(width 0.127)
		(layer "In11.Cu")
		(net "FM_PCH_P1V8_AUX_EN")
	)
	(segment
		(start 244.42547 -109.032548)
		(end 246.33174 -109.032548)
		(width 0.127)
		(layer "In11.Cu")
		(net "FM_PCH_P1V8_AUX_EN")
	)
	(segment
		(start 177.0507 -98.61423)
		(end 175.74387 -97.3074)
		(width 0.127)
		(layer "In11.Cu")
		(net "FM_PCH_P1V8_AUX_EN")
	)
	(segment
		(start 185.043318 -94.742)
		(end 188.3156 -94.742)
		(width 0.127)
		(layer "In11.Cu")
		(net "FM_PCH_P1V8_AUX_EN")
	)
	(segment
		(start 174.9552 -118.39448)
		(end 174.9552 -101.9048)
		(width 0.127)
		(layer "In11.Cu")
		(net "FM_PCH_P1V8_AUX_EN")
	)
	(segment
		(start 184.852818 -94.5515)
		(end 185.043318 -94.742)
		(width 0.127)
		(layer "In11.Cu")
		(net "FM_PCH_P1V8_AUX_EN")
	)
	(segment
		(start 175.74387 -97.3074)
		(end 172.87367 -97.3074)
		(width 0.127)
		(layer "In11.Cu")
		(net "FM_PCH_P1V8_AUX_EN")
	)
	(segment
		(start 174.9552 -101.9048)
		(end 177.0507 -99.8093)
		(width 0.127)
		(layer "In11.Cu")
		(net "FM_PCH_P1V8_AUX_EN")
	)
	(segment
		(start 172.9994 -91.2622)
		(end 181.5846 -91.2622)
		(width 0.127)
		(layer "In11.Cu")
		(net "FM_PCH_P1V8_AUX_EN")
	)
	(segment
		(start 182.753 -92.4306)
		(end 182.753 -92.837)
		(width 0.127)
		(layer "In11.Cu")
		(net "FM_PCH_P1V8_AUX_EN")
	)
	(segment
		(start 174.15764 -119.373396)
		(end 174.15764 -118.71452)
		(width 0.127)
		(layer "In11.Cu")
		(net "FM_PCH_P1V8_AUX_EN")
	)
	(segment
		(start 171.9326 -96.36633)
		(end 171.9326 -92.329)
		(width 0.127)
		(layer "In11.Cu")
		(net "FM_PCH_P1V8_AUX_EN")
	)
	(segment
		(start 211.927948 -103.42626)
		(end 212.52688 -102.827328)
		(width 0.127)
		(layer "In11.Cu")
		(net "FM_PCH_P1V8_AUX_EN")
	)
	(segment
		(start 249.481594 -112.182402)
		(end 263.530842 -112.182402)
		(width 0.127)
		(layer "In11.Cu")
		(net "FM_PCH_P1V8_AUX_EN")
	)
	(segment
		(start 277.094696 -98.618548)
		(end 311.99328 -98.618548)
		(width 0.127)
		(layer "In11.Cu")
		(net "FM_PCH_P1V8_AUX_EN")
	)
	(segment
		(start 208.802732 -103.42626)
		(end 211.927948 -103.42626)
		(width 0.127)
		(layer "In11.Cu")
		(net "FM_PCH_P1V8_AUX_EN")
	)
	(segment
		(start 174.28972 -118.58244)
		(end 174.76724 -118.58244)
		(width 0.127)
		(layer "In11.Cu")
		(net "FM_PCH_P1V8_AUX_EN")
	)
	(segment
		(start 246.33174 -109.032548)
		(end 249.481594 -112.182402)
		(width 0.127)
		(layer "In11.Cu")
		(net "FM_PCH_P1V8_AUX_EN")
	)
	(segment
		(start 182.753 -92.837)
		(end 184.4675 -94.5515)
		(width 0.127)
		(layer "In11.Cu")
		(net "FM_PCH_P1V8_AUX_EN")
	)
	(segment
		(start 208.094072 -102.7176)
		(end 208.802732 -103.42626)
		(width 0.127)
		(layer "In11.Cu")
		(net "FM_PCH_P1V8_AUX_EN")
	)
	(segment
		(start 188.3156 -94.742)
		(end 189.197488 -95.623888)
		(width 0.127)
		(layer "In11.Cu")
		(net "FM_PCH_P1V8_AUX_EN")
	)
	(segment
		(start 199.25157 -102.7176)
		(end 208.094072 -102.7176)
		(width 0.127)
		(layer "In11.Cu")
		(net "FM_PCH_P1V8_AUX_EN")
	)
	(segment
		(start 312.60288 -98.008948)
		(end 312.60288 -96.611948)
		(width 0.127)
		(layer "In11.Cu")
		(net "FM_PCH_P1V8_AUX_EN")
	)
	(segment
		(start 172.87367 -97.3074)
		(end 171.9326 -96.36633)
		(width 0.127)
		(layer "In11.Cu")
		(net "FM_PCH_P1V8_AUX_EN")
	)
	(segment
		(start 172.77588 -124.55398)
		(end 172.77588 -125.955298)
		(width 0.127)
		(layer "In11.Cu")
		(net "FM_PCH_P1V8_AUX_EN")
	)
	(segment
		(start 173.8503 -123.47956)
		(end 172.77588 -124.55398)
		(width 0.127)
		(layer "In11.Cu")
		(net "FM_PCH_P1V8_AUX_EN")
	)
	(segment
		(start 174.76724 -118.58244)
		(end 174.9552 -118.39448)
		(width 0.127)
		(layer "In11.Cu")
		(net "FM_PCH_P1V8_AUX_EN")
	)
	(segment
		(start 174.1551 -120.17502)
		(end 174.1551 -121.74982)
		(width 0.127)
		(layer "In11.Cu")
		(net "FM_PCH_P1V8_AUX_EN")
	)
	(segment
		(start 173.755558 -119.775478)
		(end 174.15764 -119.373396)
		(width 0.127)
		(layer "In11.Cu")
		(net "FM_PCH_P1V8_AUX_EN")
	)
	(segment
		(start 263.530842 -112.182402)
		(end 277.094696 -98.618548)
		(width 0.127)
		(layer "In11.Cu")
		(net "FM_PCH_P1V8_AUX_EN")
	)
	(segment
		(start 177.0507 -99.8093)
		(end 177.0507 -98.61423)
		(width 0.127)
		(layer "In11.Cu")
		(net "FM_PCH_P1V8_AUX_EN")
	)
	(segment
		(start 192.157858 -95.623888)
		(end 199.25157 -102.7176)
		(width 0.127)
		(layer "In11.Cu")
		(net "FM_PCH_P1V8_AUX_EN")
	)
	(segment
		(start 212.52688 -102.827328)
		(end 238.22025 -102.827328)
		(width 0.127)
		(layer "In11.Cu")
		(net "FM_PCH_P1V8_AUX_EN")
	)
	(segment
		(start 173.8503 -122.05462)
		(end 173.8503 -123.47956)
		(width 0.127)
		(layer "In11.Cu")
		(net "FM_PCH_P1V8_AUX_EN")
	)
	(segment
		(start 320.590672 -59.299348)
		(end 319.888362 -60.001658)
		(width 0.12954)
		(layer "F.Cu")
		(net "FM_PCH_MCRO_LDO")
	)
	(segment
		(start 324.234556 -56.523128)
		(end 323.313552 -57.444132)
		(width 0.12954)
		(layer "F.Cu")
		(net "FM_PCH_MCRO_LDO")
	)
	(segment
		(start 317.796672 -59.54522)
		(end 317.796672 -59.299348)
		(width 0.12954)
		(layer "F.Cu")
		(net "FM_PCH_MCRO_LDO")
	)
	(segment
		(start 326.438768 -55.22976)
		(end 326.168258 -55.150004)
		(width 0.0889)
		(layer "F.Cu")
		(net "FM_PCH_MCRO_LDO")
	)
	(segment
		(start 324.234556 -56.210708)
		(end 324.234556 -56.523128)
		(width 0.12954)
		(layer "F.Cu")
		(net "FM_PCH_MCRO_LDO")
	)
	(segment
		(start 321.098672 -58.791348)
		(end 320.590672 -59.299348)
		(width 0.12954)
		(layer "F.Cu")
		(net "FM_PCH_MCRO_LDO")
	)
	(segment
		(start 324.234556 -55.907432)
		(end 324.234556 -56.210708)
		(width 0.0889)
		(layer "F.Cu")
		(net "FM_PCH_MCRO_LDO")
	)
	(segment
		(start 319.888362 -60.001658)
		(end 318.63411 -60.001658)
		(width 0.12954)
		(layer "F.Cu")
		(net "FM_PCH_MCRO_LDO")
	)
	(segment
		(start 327.13295 -54.953408)
		(end 326.862694 -55.13451)
		(width 0.0889)
		(layer "F.Cu")
		(net "FM_PCH_MCRO_LDO")
	)
	(segment
		(start 326.862694 -55.13451)
		(end 326.719184 -55.22976)
		(width 0.0889)
		(layer "F.Cu")
		(net "FM_PCH_MCRO_LDO")
	)
	(segment
		(start 326.719184 -55.22976)
		(end 326.438768 -55.22976)
		(width 0.0889)
		(layer "F.Cu")
		(net "FM_PCH_MCRO_LDO")
	)
	(segment
		(start 322.222368 -58.791348)
		(end 321.098672 -58.791348)
		(width 0.12954)
		(layer "F.Cu")
		(net "FM_PCH_MCRO_LDO")
	)
	(segment
		(start 324.991984 -55.150004)
		(end 324.234556 -55.907432)
		(width 0.0889)
		(layer "F.Cu")
		(net "FM_PCH_MCRO_LDO")
	)
	(segment
		(start 326.168258 -55.150004)
		(end 324.991984 -55.150004)
		(width 0.0889)
		(layer "F.Cu")
		(net "FM_PCH_MCRO_LDO")
	)
	(segment
		(start 323.313552 -57.444132)
		(end 323.313552 -57.700164)
		(width 0.12954)
		(layer "F.Cu")
		(net "FM_PCH_MCRO_LDO")
	)
	(segment
		(start 318.63411 -60.001658)
		(end 318.48044 -59.847988)
		(width 0.12954)
		(layer "F.Cu")
		(net "FM_PCH_MCRO_LDO")
	)
	(segment
		(start 327.41489 -54.953408)
		(end 327.13295 -54.953408)
		(width 0.0889)
		(layer "F.Cu")
		(net "FM_PCH_MCRO_LDO")
	)
	(segment
		(start 318.48044 -59.847988)
		(end 318.09944 -59.847988)
		(width 0.12954)
		(layer "F.Cu")
		(net "FM_PCH_MCRO_LDO")
	)
	(segment
		(start 318.09944 -59.847988)
		(end 317.796672 -59.54522)
		(width 0.12954)
		(layer "F.Cu")
		(net "FM_PCH_MCRO_LDO")
	)
	(segment
		(start 323.313552 -57.700164)
		(end 322.222368 -58.791348)
		(width 0.12954)
		(layer "F.Cu")
		(net "FM_PCH_MCRO_LDO")
	)
	(via
		(at 318.48044 -59.847988)
		(size 0.508)
		(drill 0.254)
		(layers "F.Cu" "B.Cu")
		(net "FM_PCH_MCRO_LDO")
	)
	(segment
		(start 320.057272 -58.816748)
		(end 318.6303 -58.816748)
		(width 0.12954)
		(layer "F.Cu")
		(net "FM_PCH_IO_EXPANDER")
	)
	(segment
		(start 324.85965 -54.953408)
		(end 326.584818 -54.953408)
		(width 0.0889)
		(layer "F.Cu")
		(net "FM_PCH_IO_EXPANDER")
	)
	(segment
		(start 320.590672 -58.283348)
		(end 320.057272 -58.816748)
		(width 0.12954)
		(layer "F.Cu")
		(net "FM_PCH_IO_EXPANDER")
	)
	(segment
		(start 317.796672 -58.283348)
		(end 317.796672 -57.775348)
		(width 0.12954)
		(layer "F.Cu")
		(net "FM_PCH_IO_EXPANDER")
	)
	(segment
		(start 323.838316 -55.974742)
		(end 324.85965 -54.953408)
		(width 0.0889)
		(layer "F.Cu")
		(net "FM_PCH_IO_EXPANDER")
	)
	(segment
		(start 320.725292 -58.148728)
		(end 321.422776 -58.148728)
		(width 0.12954)
		(layer "F.Cu")
		(net "FM_PCH_IO_EXPANDER")
	)
	(segment
		(start 321.422776 -58.148728)
		(end 321.796156 -57.775348)
		(width 0.12954)
		(layer "F.Cu")
		(net "FM_PCH_IO_EXPANDER")
	)
	(segment
		(start 323.838316 -56.286654)
		(end 323.838316 -55.974742)
		(width 0.0889)
		(layer "F.Cu")
		(net "FM_PCH_IO_EXPANDER")
	)
	(segment
		(start 322.349622 -57.775348)
		(end 323.838316 -56.286654)
		(width 0.12954)
		(layer "F.Cu")
		(net "FM_PCH_IO_EXPANDER")
	)
	(segment
		(start 318.6303 -58.816748)
		(end 318.37376 -58.560208)
		(width 0.12954)
		(layer "F.Cu")
		(net "FM_PCH_IO_EXPANDER")
	)
	(segment
		(start 320.590672 -58.283348)
		(end 320.725292 -58.148728)
		(width 0.12954)
		(layer "F.Cu")
		(net "FM_PCH_IO_EXPANDER")
	)
	(segment
		(start 318.37376 -58.560208)
		(end 318.073532 -58.560208)
		(width 0.12954)
		(layer "F.Cu")
		(net "FM_PCH_IO_EXPANDER")
	)
	(segment
		(start 321.796156 -57.775348)
		(end 322.349622 -57.775348)
		(width 0.12954)
		(layer "F.Cu")
		(net "FM_PCH_IO_EXPANDER")
	)
	(segment
		(start 318.073532 -58.560208)
		(end 317.796672 -58.283348)
		(width 0.12954)
		(layer "F.Cu")
		(net "FM_PCH_IO_EXPANDER")
	)
	(via
		(at 318.37376 -58.560208)
		(size 0.508)
		(drill 0.254)
		(layers "F.Cu" "B.Cu")
		(net "FM_PCH_IO_EXPANDER")
	)
	(segment
		(start 320.052192 -51.550824)
		(end 318.825372 -51.550824)
		(width 0.12954)
		(layer "F.Cu")
		(net "FM_PCH_GLB_RST_WARN_N")
	)
	(segment
		(start 323.282564 -50.283618)
		(end 322.613274 -50.952908)
		(width 0.0889)
		(layer "F.Cu")
		(net "FM_PCH_GLB_RST_WARN_N")
	)
	(segment
		(start 325.474838 -49.950878)
		(end 325.142098 -50.283618)
		(width 0.0889)
		(layer "F.Cu")
		(net "FM_PCH_GLB_RST_WARN_N")
	)
	(segment
		(start 317.940436 -51.145948)
		(end 317.889636 -51.196748)
		(width 0.12954)
		(layer "F.Cu")
		(net "FM_PCH_GLB_RST_WARN_N")
	)
	(segment
		(start 326.584818 -49.950878)
		(end 325.474838 -49.950878)
		(width 0.0889)
		(layer "F.Cu")
		(net "FM_PCH_GLB_RST_WARN_N")
	)
	(segment
		(start 322.613274 -50.952908)
		(end 322.239386 -51.326796)
		(width 0.12954)
		(layer "F.Cu")
		(net "FM_PCH_GLB_RST_WARN_N")
	)
	(segment
		(start 322.239386 -51.326796)
		(end 320.27622 -51.326796)
		(width 0.12954)
		(layer "F.Cu")
		(net "FM_PCH_GLB_RST_WARN_N")
	)
	(segment
		(start 317.889636 -51.196748)
		(end 317.796672 -51.196748)
		(width 0.12954)
		(layer "F.Cu")
		(net "FM_PCH_GLB_RST_WARN_N")
	)
	(segment
		(start 325.142098 -50.283618)
		(end 323.282564 -50.283618)
		(width 0.0889)
		(layer "F.Cu")
		(net "FM_PCH_GLB_RST_WARN_N")
	)
	(segment
		(start 318.825372 -51.550824)
		(end 318.420496 -51.145948)
		(width 0.12954)
		(layer "F.Cu")
		(net "FM_PCH_GLB_RST_WARN_N")
	)
	(segment
		(start 320.27622 -51.326796)
		(end 320.052192 -51.550824)
		(width 0.12954)
		(layer "F.Cu")
		(net "FM_PCH_GLB_RST_WARN_N")
	)
	(segment
		(start 193.93281 -120.767348)
		(end 193.78041 -120.614948)
		(width 0.12954)
		(layer "F.Cu")
		(net "FM_PCH_GLB_RST_WARN_N")
	)
	(segment
		(start 194.40144 -120.754648)
		(end 194.38874 -120.767348)
		(width 0.12954)
		(layer "F.Cu")
		(net "FM_PCH_GLB_RST_WARN_N")
	)
	(segment
		(start 318.420496 -51.145948)
		(end 317.940436 -51.145948)
		(width 0.12954)
		(layer "F.Cu")
		(net "FM_PCH_GLB_RST_WARN_N")
	)
	(segment
		(start 194.38874 -120.767348)
		(end 193.93281 -120.767348)
		(width 0.12954)
		(layer "F.Cu")
		(net "FM_PCH_GLB_RST_WARN_N")
	)
	(via
		(at 194.40144 -120.754648)
		(size 0.508)
		(drill 0.254)
		(layers "F.Cu" "B.Cu")
		(net "FM_PCH_GLB_RST_WARN_N")
	)
	(via
		(at 324.70852 -117.693948)
		(size 0.508)
		(drill 0.254)
		(layers "F.Cu" "B.Cu")
		(net "FM_PCH_GLB_RST_WARN_N")
	)
	(via
		(at 318.420496 -51.145948)
		(size 0.508)
		(drill 0.254)
		(layers "F.Cu" "B.Cu")
		(net "FM_PCH_GLB_RST_WARN_N")
	)
	(segment
		(start 321.25412 -70.152768)
		(end 321.25412 -67.963288)
		(width 0.127)
		(layer "In2.Cu")
		(net "FM_PCH_GLB_RST_WARN_N")
	)
	(segment
		(start 321.25412 -67.963288)
		(end 317.70828 -64.417448)
		(width 0.127)
		(layer "In2.Cu")
		(net "FM_PCH_GLB_RST_WARN_N")
	)
	(segment
		(start 317.70828 -51.858164)
		(end 318.420496 -51.145948)
		(width 0.127)
		(layer "In2.Cu")
		(net "FM_PCH_GLB_RST_WARN_N")
	)
	(segment
		(start 324.70852 -117.693948)
		(end 324.70852 -73.607168)
		(width 0.127)
		(layer "In2.Cu")
		(net "FM_PCH_GLB_RST_WARN_N")
	)
	(segment
		(start 324.70852 -73.607168)
		(end 321.25412 -70.152768)
		(width 0.127)
		(layer "In2.Cu")
		(net "FM_PCH_GLB_RST_WARN_N")
	)
	(segment
		(start 317.70828 -64.417448)
		(end 317.70828 -51.858164)
		(width 0.127)
		(layer "In2.Cu")
		(net "FM_PCH_GLB_RST_WARN_N")
	)
	(segment
		(start 270.765016 -119.471948)
		(end 269.075916 -121.161048)
		(width 0.127)
		(layer "In15.Cu")
		(net "FM_PCH_GLB_RST_WARN_N")
	)
	(segment
		(start 194.41414 -120.767348)
		(end 194.40144 -120.754648)
		(width 0.127)
		(layer "In15.Cu")
		(net "FM_PCH_GLB_RST_WARN_N")
	)
	(segment
		(start 283.505148 -119.471948)
		(end 270.765016 -119.471948)
		(width 0.127)
		(layer "In15.Cu")
		(net "FM_PCH_GLB_RST_WARN_N")
	)
	(segment
		(start 269.075916 -121.161048)
		(end 248.543064 -121.161048)
		(width 0.127)
		(layer "In15.Cu")
		(net "FM_PCH_GLB_RST_WARN_N")
	)
	(segment
		(start 232.5878 -117.254528)
		(end 216.300304 -117.254528)
		(width 0.127)
		(layer "In15.Cu")
		(net "FM_PCH_GLB_RST_WARN_N")
	)
	(segment
		(start 196.38518 -121.603008)
		(end 195.54952 -120.767348)
		(width 0.127)
		(layer "In15.Cu")
		(net "FM_PCH_GLB_RST_WARN_N")
	)
	(segment
		(start 207.733392 -121.603008)
		(end 196.38518 -121.603008)
		(width 0.127)
		(layer "In15.Cu")
		(net "FM_PCH_GLB_RST_WARN_N")
	)
	(segment
		(start 216.300304 -117.254528)
		(end 212.701632 -120.8532)
		(width 0.127)
		(layer "In15.Cu")
		(net "FM_PCH_GLB_RST_WARN_N")
	)
	(segment
		(start 284.317948 -118.659148)
		(end 283.505148 -119.471948)
		(width 0.127)
		(layer "In15.Cu")
		(net "FM_PCH_GLB_RST_WARN_N")
	)
	(segment
		(start 195.54952 -120.767348)
		(end 194.41414 -120.767348)
		(width 0.127)
		(layer "In15.Cu")
		(net "FM_PCH_GLB_RST_WARN_N")
	)
	(segment
		(start 246.699024 -119.317008)
		(end 237.97514 -119.317008)
		(width 0.127)
		(layer "In15.Cu")
		(net "FM_PCH_GLB_RST_WARN_N")
	)
	(segment
		(start 324.70852 -117.693948)
		(end 323.74332 -118.659148)
		(width 0.127)
		(layer "In15.Cu")
		(net "FM_PCH_GLB_RST_WARN_N")
	)
	(segment
		(start 237.01502 -118.356888)
		(end 233.69016 -118.356888)
		(width 0.127)
		(layer "In15.Cu")
		(net "FM_PCH_GLB_RST_WARN_N")
	)
	(segment
		(start 233.69016 -118.356888)
		(end 232.5878 -117.254528)
		(width 0.127)
		(layer "In15.Cu")
		(net "FM_PCH_GLB_RST_WARN_N")
	)
	(segment
		(start 208.4832 -120.8532)
		(end 207.733392 -121.603008)
		(width 0.127)
		(layer "In15.Cu")
		(net "FM_PCH_GLB_RST_WARN_N")
	)
	(segment
		(start 248.543064 -121.161048)
		(end 246.699024 -119.317008)
		(width 0.127)
		(layer "In15.Cu")
		(net "FM_PCH_GLB_RST_WARN_N")
	)
	(segment
		(start 323.74332 -118.659148)
		(end 284.317948 -118.659148)
		(width 0.127)
		(layer "In15.Cu")
		(net "FM_PCH_GLB_RST_WARN_N")
	)
	(segment
		(start 212.701632 -120.8532)
		(end 208.4832 -120.8532)
		(width 0.127)
		(layer "In15.Cu")
		(net "FM_PCH_GLB_RST_WARN_N")
	)
	(segment
		(start 237.97514 -119.317008)
		(end 237.01502 -118.356888)
		(width 0.127)
		(layer "In15.Cu")
		(net "FM_PCH_GLB_RST_WARN_N")
	)
	(segment
		(start 318.946276 -56.821578)
		(end 320.020442 -56.821578)
		(width 0.12954)
		(layer "F.Cu")
		(net "FM_PCH_EXTERNALCLKMODE")
	)
	(segment
		(start 317.796672 -56.759348)
		(end 317.797942 -56.760618)
		(width 0.12954)
		(layer "F.Cu")
		(net "FM_PCH_EXTERNALCLKMODE")
	)
	(segment
		(start 320.020442 -56.821578)
		(end 320.590672 -56.251348)
		(width 0.12954)
		(layer "F.Cu")
		(net "FM_PCH_EXTERNALCLKMODE")
	)
	(segment
		(start 317.797942 -56.760618)
		(end 318.885316 -56.760618)
		(width 0.12954)
		(layer "F.Cu")
		(net "FM_PCH_EXTERNALCLKMODE")
	)
	(segment
		(start 324.913244 -54.243986)
		(end 325.295006 -54.243986)
		(width 0.0889)
		(layer "F.Cu")
		(net "FM_PCH_EXTERNALCLKMODE")
	)
	(segment
		(start 323.381116 -55.418228)
		(end 323.739002 -55.418228)
		(width 0.0889)
		(layer "F.Cu")
		(net "FM_PCH_EXTERNALCLKMODE")
	)
	(segment
		(start 323.739002 -55.418228)
		(end 324.913244 -54.243986)
		(width 0.0889)
		(layer "F.Cu")
		(net "FM_PCH_EXTERNALCLKMODE")
	)
	(segment
		(start 321.89801 -56.058054)
		(end 321.704716 -56.251348)
		(width 0.12954)
		(layer "F.Cu")
		(net "FM_PCH_EXTERNALCLKMODE")
	)
	(segment
		(start 325.295006 -54.243986)
		(end 325.484236 -54.433216)
		(width 0.0889)
		(layer "F.Cu")
		(net "FM_PCH_EXTERNALCLKMODE")
	)
	(segment
		(start 318.885316 -56.760618)
		(end 318.946276 -56.821578)
		(width 0.12954)
		(layer "F.Cu")
		(net "FM_PCH_EXTERNALCLKMODE")
	)
	(segment
		(start 321.89801 -56.058054)
		(end 322.127626 -56.058054)
		(width 0.12954)
		(layer "F.Cu")
		(net "FM_PCH_EXTERNALCLKMODE")
	)
	(segment
		(start 322.767452 -55.418228)
		(end 323.381116 -55.418228)
		(width 0.12954)
		(layer "F.Cu")
		(net "FM_PCH_EXTERNALCLKMODE")
	)
	(segment
		(start 322.127626 -56.058054)
		(end 322.767452 -55.418228)
		(width 0.12954)
		(layer "F.Cu")
		(net "FM_PCH_EXTERNALCLKMODE")
	)
	(segment
		(start 326.128126 -54.453028)
		(end 326.999854 -54.453028)
		(width 0.0889)
		(layer "F.Cu")
		(net "FM_PCH_EXTERNALCLKMODE")
	)
	(segment
		(start 321.704716 -56.251348)
		(end 320.590672 -56.251348)
		(width 0.12954)
		(layer "F.Cu")
		(net "FM_PCH_EXTERNALCLKMODE")
	)
	(segment
		(start 326.108314 -54.433216)
		(end 326.128126 -54.453028)
		(width 0.0889)
		(layer "F.Cu")
		(net "FM_PCH_EXTERNALCLKMODE")
	)
	(segment
		(start 325.484236 -54.433216)
		(end 326.108314 -54.433216)
		(width 0.0889)
		(layer "F.Cu")
		(net "FM_PCH_EXTERNALCLKMODE")
	)
	(via
		(at 321.89801 -56.058054)
		(size 0.508)
		(drill 0.254)
		(layers "F.Cu" "B.Cu")
		(net "FM_PCH_EXTERNALCLKMODE")
	)
	(segment
		(start 316.59068 -56.251348)
		(end 317.70828 -56.251348)
		(width 0.12954)
		(layer "F.Cu")
		(net "FM_PCH_DFXTESTMODE")
	)
	(segment
		(start 327.052686 -52.952396)
		(end 327.41489 -52.952396)
		(width 0.0889)
		(layer "F.Cu")
		(net "FM_PCH_DFXTESTMODE")
	)
	(segment
		(start 326.752966 -53.234844)
		(end 326.88022 -53.124862)
		(width 0.0889)
		(layer "F.Cu")
		(net "FM_PCH_DFXTESTMODE")
	)
	(segment
		(start 326.415146 -53.234844)
		(end 326.752966 -53.234844)
		(width 0.0889)
		(layer "F.Cu")
		(net "FM_PCH_DFXTESTMODE")
	)
	(segment
		(start 326.228202 -53.166518)
		(end 326.415146 -53.234844)
		(width 0.0889)
		(layer "F.Cu")
		(net "FM_PCH_DFXTESTMODE")
	)
	(segment
		(start 317.796672 -55.794148)
		(end 318.595756 -54.995064)
		(width 0.12954)
		(layer "F.Cu")
		(net "FM_PCH_DFXTESTMODE")
	)
	(segment
		(start 320.810636 -54.613048)
		(end 320.893948 -54.69636)
		(width 0.12954)
		(layer "F.Cu")
		(net "FM_PCH_DFXTESTMODE")
	)
	(segment
		(start 318.595756 -54.897528)
		(end 318.880236 -54.613048)
		(width 0.12954)
		(layer "F.Cu")
		(net "FM_PCH_DFXTESTMODE")
	)
	(segment
		(start 315.566806 -56.467248)
		(end 316.37478 -56.467248)
		(width 0.12954)
		(layer "F.Cu")
		(net "FM_PCH_DFXTESTMODE")
	)
	(segment
		(start 318.880236 -54.613048)
		(end 320.810636 -54.613048)
		(width 0.12954)
		(layer "F.Cu")
		(net "FM_PCH_DFXTESTMODE")
	)
	(segment
		(start 315.199776 -56.105806)
		(end 315.564012 -56.470042)
		(width 0.12954)
		(layer "F.Cu")
		(net "FM_PCH_DFXTESTMODE")
	)
	(segment
		(start 317.796672 -56.162956)
		(end 317.796672 -55.794148)
		(width 0.12954)
		(layer "F.Cu")
		(net "FM_PCH_DFXTESTMODE")
	)
	(segment
		(start 316.37478 -56.467248)
		(end 316.59068 -56.251348)
		(width 0.12954)
		(layer "F.Cu")
		(net "FM_PCH_DFXTESTMODE")
	)
	(segment
		(start 324.738746 -53.166518)
		(end 326.228202 -53.166518)
		(width 0.0889)
		(layer "F.Cu")
		(net "FM_PCH_DFXTESTMODE")
	)
	(segment
		(start 323.388482 -53.711348)
		(end 324.193916 -53.711348)
		(width 0.0889)
		(layer "F.Cu")
		(net "FM_PCH_DFXTESTMODE")
	)
	(segment
		(start 315.564012 -56.470042)
		(end 315.566806 -56.467248)
		(width 0.12954)
		(layer "F.Cu")
		(net "FM_PCH_DFXTESTMODE")
	)
	(segment
		(start 317.70828 -56.251348)
		(end 317.796672 -56.162956)
		(width 0.12954)
		(layer "F.Cu")
		(net "FM_PCH_DFXTESTMODE")
	)
	(segment
		(start 320.893948 -54.69636)
		(end 322.40347 -54.69636)
		(width 0.12954)
		(layer "F.Cu")
		(net "FM_PCH_DFXTESTMODE")
	)
	(segment
		(start 322.955412 -54.144418)
		(end 323.388482 -53.711348)
		(width 0.0889)
		(layer "F.Cu")
		(net "FM_PCH_DFXTESTMODE")
	)
	(segment
		(start 318.595756 -54.995064)
		(end 318.595756 -54.897528)
		(width 0.12954)
		(layer "F.Cu")
		(net "FM_PCH_DFXTESTMODE")
	)
	(segment
		(start 315.199776 -55.546244)
		(end 315.199776 -56.105806)
		(width 0.12954)
		(layer "F.Cu")
		(net "FM_PCH_DFXTESTMODE")
	)
	(segment
		(start 315.510672 -55.235348)
		(end 315.199776 -55.546244)
		(width 0.12954)
		(layer "F.Cu")
		(net "FM_PCH_DFXTESTMODE")
	)
	(segment
		(start 326.88022 -53.124862)
		(end 327.052686 -52.952396)
		(width 0.0889)
		(layer "F.Cu")
		(net "FM_PCH_DFXTESTMODE")
	)
	(segment
		(start 322.40347 -54.69636)
		(end 322.955412 -54.144418)
		(width 0.12954)
		(layer "F.Cu")
		(net "FM_PCH_DFXTESTMODE")
	)
	(segment
		(start 324.193916 -53.711348)
		(end 324.738746 -53.166518)
		(width 0.0889)
		(layer "F.Cu")
		(net "FM_PCH_DFXTESTMODE")
	)
	(via
		(at 315.564012 -56.470042)
		(size 0.762)
		(drill 0.381)
		(layers "F.Cu" "B.Cu")
		(net "FM_PCH_DFXTESTMODE")
	)
	(segment
		(start 203.364084 -82.89798)
		(end 200.15454 -79.688436)
		(width 0.12954)
		(layer "F.Cu")
		(net "FM_PCH_CRASHLOG_TRIG_R_N")
	)
	(segment
		(start 188.056266 -110.028228)
		(end 187.803536 -109.775498)
		(width 0.12954)
		(layer "F.Cu")
		(net "FM_PCH_CRASHLOG_TRIG_R_N")
	)
	(segment
		(start 313.76112 -48.570388)
		(end 314.687712 -48.570388)
		(width 0.12954)
		(layer "F.Cu")
		(net "FM_PCH_CRASHLOG_TRIG_R_N")
	)
	(segment
		(start 200.126092 -106.81716)
		(end 198.812404 -108.130848)
		(width 0.12954)
		(layer "F.Cu")
		(net "FM_PCH_CRASHLOG_TRIG_R_N")
	)
	(segment
		(start 200.15454 -79.688436)
		(end 199.24141 -79.688436)
		(width 0.12954)
		(layer "F.Cu")
		(net "FM_PCH_CRASHLOG_TRIG_R_N")
	)
	(segment
		(start 202.954128 -106.81716)
		(end 200.126092 -106.81716)
		(width 0.12954)
		(layer "F.Cu")
		(net "FM_PCH_CRASHLOG_TRIG_R_N")
	)
	(segment
		(start 313.11088 -47.920148)
		(end 313.76112 -48.570388)
		(width 0.12954)
		(layer "F.Cu")
		(net "FM_PCH_CRASHLOG_TRIG_R_N")
	)
	(segment
		(start 203.120244 -106.983276)
		(end 202.954128 -106.81716)
		(width 0.12954)
		(layer "F.Cu")
		(net "FM_PCH_CRASHLOG_TRIG_R_N")
	)
	(segment
		(start 311.295796 -47.920148)
		(end 313.11088 -47.920148)
		(width 0.12954)
		(layer "F.Cu")
		(net "FM_PCH_CRASHLOG_TRIG_R_N")
	)
	(segment
		(start 192.496694 -108.130848)
		(end 191.17818 -109.449362)
		(width 0.12954)
		(layer "F.Cu")
		(net "FM_PCH_CRASHLOG_TRIG_R_N")
	)
	(segment
		(start 190.97244 -110.028228)
		(end 188.056266 -110.028228)
		(width 0.12954)
		(layer "F.Cu")
		(net "FM_PCH_CRASHLOG_TRIG_R_N")
	)
	(segment
		(start 203.364084 -90.149934)
		(end 203.364084 -82.89798)
		(width 0.12954)
		(layer "F.Cu")
		(net "FM_PCH_CRASHLOG_TRIG_R_N")
	)
	(segment
		(start 191.17818 -109.449362)
		(end 191.17818 -109.822488)
		(width 0.12954)
		(layer "F.Cu")
		(net "FM_PCH_CRASHLOG_TRIG_R_N")
	)
	(segment
		(start 187.803536 -109.775498)
		(end 186.955684 -109.775498)
		(width 0.12954)
		(layer "F.Cu")
		(net "FM_PCH_CRASHLOG_TRIG_R_N")
	)
	(segment
		(start 198.812404 -108.130848)
		(end 192.496694 -108.130848)
		(width 0.12954)
		(layer "F.Cu")
		(net "FM_PCH_CRASHLOG_TRIG_R_N")
	)
	(segment
		(start 314.687712 -48.570388)
		(end 314.70219 -48.584866)
		(width 0.12954)
		(layer "F.Cu")
		(net "FM_PCH_CRASHLOG_TRIG_R_N")
	)
	(segment
		(start 191.17818 -109.822488)
		(end 190.97244 -110.028228)
		(width 0.12954)
		(layer "F.Cu")
		(net "FM_PCH_CRASHLOG_TRIG_R_N")
	)
	(segment
		(start 209.1944 -106.983276)
		(end 203.120244 -106.983276)
		(width 0.12954)
		(layer "F.Cu")
		(net "FM_PCH_CRASHLOG_TRIG_R_N")
	)
	(via
		(at 209.1944 -106.983276)
		(size 0.508)
		(drill 0.254)
		(layers "F.Cu" "B.Cu")
		(net "FM_PCH_CRASHLOG_TRIG_R_N")
	)
	(via
		(at 199.24141 -79.688436)
		(size 0.508)
		(drill 0.254)
		(layers "F.Cu" "B.Cu")
		(net "FM_PCH_CRASHLOG_TRIG_R_N")
	)
	(via
		(at 311.295796 -47.920148)
		(size 0.508)
		(drill 0.254)
		(layers "F.Cu" "B.Cu")
		(net "FM_PCH_CRASHLOG_TRIG_R_N")
	)
	(via
		(at 290.692078 -57.728358)
		(size 0.508)
		(drill 0.254)
		(layers "F.Cu" "B.Cu")
		(net "FM_PCH_CRASHLOG_TRIG_R_N")
	)
	(via
		(at 203.364084 -90.149934)
		(size 0.508)
		(drill 0.254)
		(layers "F.Cu" "B.Cu")
		(net "FM_PCH_CRASHLOG_TRIG_R_N")
	)
	(segment
		(start 205.725522 -89.675208)
		(end 210.034124 -93.98381)
		(width 0.127)
		(layer "In2.Cu")
		(net "FM_PCH_CRASHLOG_TRIG_R_N")
	)
	(segment
		(start 203.364084 -89.802208)
		(end 203.491084 -89.675208)
		(width 0.127)
		(layer "In2.Cu")
		(net "FM_PCH_CRASHLOG_TRIG_R_N")
	)
	(segment
		(start 210.034124 -93.98381)
		(end 210.034124 -106.143552)
		(width 0.127)
		(layer "In2.Cu")
		(net "FM_PCH_CRASHLOG_TRIG_R_N")
	)
	(segment
		(start 210.034124 -106.143552)
		(end 209.1944 -106.983276)
		(width 0.127)
		(layer "In2.Cu")
		(net "FM_PCH_CRASHLOG_TRIG_R_N")
	)
	(segment
		(start 203.364084 -90.149934)
		(end 203.364084 -89.802208)
		(width 0.127)
		(layer "In2.Cu")
		(net "FM_PCH_CRASHLOG_TRIG_R_N")
	)
	(segment
		(start 203.491084 -89.675208)
		(end 205.725522 -89.675208)
		(width 0.127)
		(layer "In2.Cu")
		(net "FM_PCH_CRASHLOG_TRIG_R_N")
	)
	(segment
		(start 275.99386 -81.95818)
		(end 244.244622 -81.95818)
		(width 0.127)
		(layer "In6.Cu")
		(net "FM_PCH_CRASHLOG_TRIG_R_N")
	)
	(segment
		(start 244.244622 -81.95818)
		(end 239.068864 -87.133938)
		(width 0.127)
		(layer "In6.Cu")
		(net "FM_PCH_CRASHLOG_TRIG_R_N")
	)
	(segment
		(start 290.513008 -57.21096)
		(end 288.72688 -57.21096)
		(width 0.127)
		(layer "In6.Cu")
		(net "FM_PCH_CRASHLOG_TRIG_R_N")
	)
	(segment
		(start 213.380574 -87.133938)
		(end 206.693008 -80.446372)
		(width 0.127)
		(layer "In6.Cu")
		(net "FM_PCH_CRASHLOG_TRIG_R_N")
	)
	(segment
		(start 283.46273 -74.48931)
		(end 275.99386 -81.95818)
		(width 0.127)
		(layer "In6.Cu")
		(net "FM_PCH_CRASHLOG_TRIG_R_N")
	)
	(segment
		(start 290.692078 -57.39003)
		(end 290.513008 -57.21096)
		(width 0.127)
		(layer "In6.Cu")
		(net "FM_PCH_CRASHLOG_TRIG_R_N")
	)
	(segment
		(start 283.46273 -62.47511)
		(end 283.46273 -74.48931)
		(width 0.127)
		(layer "In6.Cu")
		(net "FM_PCH_CRASHLOG_TRIG_R_N")
	)
	(segment
		(start 239.068864 -87.133938)
		(end 213.380574 -87.133938)
		(width 0.127)
		(layer "In6.Cu")
		(net "FM_PCH_CRASHLOG_TRIG_R_N")
	)
	(segment
		(start 288.72688 -57.21096)
		(end 283.46273 -62.47511)
		(width 0.127)
		(layer "In6.Cu")
		(net "FM_PCH_CRASHLOG_TRIG_R_N")
	)
	(segment
		(start 290.692078 -57.728358)
		(end 290.692078 -57.39003)
		(width 0.127)
		(layer "In6.Cu")
		(net "FM_PCH_CRASHLOG_TRIG_R_N")
	)
	(segment
		(start 206.693008 -80.446372)
		(end 199.999346 -80.446372)
		(width 0.127)
		(layer "In6.Cu")
		(net "FM_PCH_CRASHLOG_TRIG_R_N")
	)
	(segment
		(start 199.999346 -80.446372)
		(end 199.24141 -79.688436)
		(width 0.127)
		(layer "In6.Cu")
		(net "FM_PCH_CRASHLOG_TRIG_R_N")
	)
	(segment
		(start 311.295796 -47.920148)
		(end 309.40883 -47.920148)
		(width 0.127)
		(layer "In13.Cu")
		(net "FM_PCH_CRASHLOG_TRIG_R_N")
	)
	(segment
		(start 290.692078 -54.61762)
		(end 290.692078 -57.728358)
		(width 0.127)
		(layer "In13.Cu")
		(net "FM_PCH_CRASHLOG_TRIG_R_N")
	)
	(segment
		(start 308.621176 -48.707802)
		(end 305.764946 -48.707802)
		(width 0.127)
		(layer "In13.Cu")
		(net "FM_PCH_CRASHLOG_TRIG_R_N")
	)
	(segment
		(start 295.202102 -51.443128)
		(end 293.86657 -51.443128)
		(width 0.127)
		(layer "In13.Cu")
		(net "FM_PCH_CRASHLOG_TRIG_R_N")
	)
	(segment
		(start 309.40883 -47.920148)
		(end 308.621176 -48.707802)
		(width 0.127)
		(layer "In13.Cu")
		(net "FM_PCH_CRASHLOG_TRIG_R_N")
	)
	(segment
		(start 296.817542 -49.827688)
		(end 295.202102 -51.443128)
		(width 0.127)
		(layer "In13.Cu")
		(net "FM_PCH_CRASHLOG_TRIG_R_N")
	)
	(segment
		(start 304.64506 -49.827688)
		(end 296.817542 -49.827688)
		(width 0.127)
		(layer "In13.Cu")
		(net "FM_PCH_CRASHLOG_TRIG_R_N")
	)
	(segment
		(start 293.86657 -51.443128)
		(end 290.692078 -54.61762)
		(width 0.127)
		(layer "In13.Cu")
		(net "FM_PCH_CRASHLOG_TRIG_R_N")
	)
	(segment
		(start 305.764946 -48.707802)
		(end 304.64506 -49.827688)
		(width 0.127)
		(layer "In13.Cu")
		(net "FM_PCH_CRASHLOG_TRIG_R_N")
	)
	(segment
		(start 320.147696 -48.951642)
		(end 320.178684 -48.920654)
		(width 0.12954)
		(layer "F.Cu")
		(net "FM_PCH_CRASHLOG_TRIG_N")
	)
	(segment
		(start 326.425814 -48.226726)
		(end 326.718422 -48.226726)
		(width 0.0889)
		(layer "F.Cu")
		(net "FM_PCH_CRASHLOG_TRIG_N")
	)
	(segment
		(start 326.07504 -48.123348)
		(end 326.425814 -48.226726)
		(width 0.0889)
		(layer "F.Cu")
		(net "FM_PCH_CRASHLOG_TRIG_N")
	)
	(segment
		(start 320.178684 -48.920654)
		(end 320.632328 -48.920654)
		(width 0.12954)
		(layer "F.Cu")
		(net "FM_PCH_CRASHLOG_TRIG_N")
	)
	(segment
		(start 326.718422 -48.226726)
		(end 327.132696 -47.95012)
		(width 0.0889)
		(layer "F.Cu")
		(net "FM_PCH_CRASHLOG_TRIG_N")
	)
	(segment
		(start 321.115944 -48.920654)
		(end 321.69227 -48.344328)
		(width 0.12954)
		(layer "F.Cu")
		(net "FM_PCH_CRASHLOG_TRIG_N")
	)
	(segment
		(start 323.136768 -48.123348)
		(end 326.07504 -48.123348)
		(width 0.0889)
		(layer "F.Cu")
		(net "FM_PCH_CRASHLOG_TRIG_N")
	)
	(segment
		(start 320.632328 -48.920654)
		(end 321.115944 -48.920654)
		(width 0.12954)
		(layer "F.Cu")
		(net "FM_PCH_CRASHLOG_TRIG_N")
	)
	(segment
		(start 316.456568 -48.584866)
		(end 316.823344 -48.951642)
		(width 0.12954)
		(layer "F.Cu")
		(net "FM_PCH_CRASHLOG_TRIG_N")
	)
	(segment
		(start 321.69227 -48.344328)
		(end 322.915788 -48.344328)
		(width 0.12954)
		(layer "F.Cu")
		(net "FM_PCH_CRASHLOG_TRIG_N")
	)
	(segment
		(start 327.132696 -47.95012)
		(end 327.41489 -47.95012)
		(width 0.0889)
		(layer "F.Cu")
		(net "FM_PCH_CRASHLOG_TRIG_N")
	)
	(segment
		(start 315.50229 -48.584866)
		(end 316.456568 -48.584866)
		(width 0.12954)
		(layer "F.Cu")
		(net "FM_PCH_CRASHLOG_TRIG_N")
	)
	(segment
		(start 316.823344 -48.951642)
		(end 320.147696 -48.951642)
		(width 0.12954)
		(layer "F.Cu")
		(net "FM_PCH_CRASHLOG_TRIG_N")
	)
	(segment
		(start 322.915788 -48.344328)
		(end 323.136768 -48.123348)
		(width 0.0889)
		(layer "F.Cu")
		(net "FM_PCH_CRASHLOG_TRIG_N")
	)
	(via
		(at 320.632328 -48.920654)
		(size 0.762)
		(drill 0.381)
		(layers "F.Cu" "B.Cu")
		(net "FM_PCH_CRASHLOG_TRIG_N")
	)
	(segment
		(start 328.525886 -57.070752)
		(end 328.244962 -56.95442)
		(width 0.12954)
		(layer "F.Cu")
		(net "FM_PCH_CPU_PWR_DEBUG_N")
	)
	(segment
		(start 328.766678 -57.070752)
		(end 328.525886 -57.070752)
		(width 0.12954)
		(layer "F.Cu")
		(net "FM_PCH_CPU_PWR_DEBUG_N")
	)
	(via
		(at 325.154036 -59.742324)
		(size 0.6604)
		(drill 0.3302)
		(layers "F.Cu" "B.Cu")
		(net "FM_PCH_CPU_PWR_DEBUG_N")
	)
	(via
		(at 328.766678 -57.070752)
		(size 0.4572)
		(drill 0.2032)
		(layers "F.Cu" "B.Cu")
		(net "FM_PCH_CPU_PWR_DEBUG_N")
	)
	(segment
		(start 328.37882 -57.45861)
		(end 327.58761 -57.45861)
		(width 0.12954)
		(layer "B.Cu")
		(net "FM_PCH_CPU_PWR_DEBUG_N")
	)
	(segment
		(start 327.58761 -57.45861)
		(end 326.909938 -58.136282)
		(width 0.12954)
		(layer "B.Cu")
		(net "FM_PCH_CPU_PWR_DEBUG_N")
	)
	(segment
		(start 328.766678 -57.070752)
		(end 328.37882 -57.45861)
		(width 0.12954)
		(layer "B.Cu")
		(net "FM_PCH_CPU_PWR_DEBUG_N")
	)
	(segment
		(start 325.709026 -59.742324)
		(end 325.154036 -59.742324)
		(width 0.12954)
		(layer "B.Cu")
		(net "FM_PCH_CPU_PWR_DEBUG_N")
	)
	(segment
		(start 325.154036 -59.742324)
		(end 323.401182 -59.742324)
		(width 0.12954)
		(layer "B.Cu")
		(net "FM_PCH_CPU_PWR_DEBUG_N")
	)
	(segment
		(start 326.909938 -58.136282)
		(end 326.909938 -58.541412)
		(width 0.12954)
		(layer "B.Cu")
		(net "FM_PCH_CPU_PWR_DEBUG_N")
	)
	(segment
		(start 326.909938 -58.541412)
		(end 325.709026 -59.742324)
		(width 0.12954)
		(layer "B.Cu")
		(net "FM_PCH_CPU_PWR_DEBUG_N")
	)
	(segment
		(start 334.864456 -42.811446)
		(end 334.325468 -42.811446)
		(width 0.12954)
		(layer "F.Cu")
		(net "FM_PCH_CONSENT_STRAP_N")
	)
	(segment
		(start 385.316222 -60.735464)
		(end 384.15468 -60.735464)
		(width 0.12954)
		(layer "F.Cu")
		(net "FM_PCH_CONSENT_STRAP_N")
	)
	(via
		(at 353.8855 -23.825708)
		(size 0.508)
		(drill 0.254)
		(layers "F.Cu" "B.Cu")
		(net "FM_PCH_CONSENT_STRAP_N")
	)
	(via
		(at 334.325468 -42.811446)
		(size 0.4572)
		(drill 0.2032)
		(layers "F.Cu" "B.Cu")
		(net "FM_PCH_CONSENT_STRAP_N")
	)
	(via
		(at 384.15468 -60.735464)
		(size 0.508)
		(drill 0.254)
		(layers "F.Cu" "B.Cu")
		(net "FM_PCH_CONSENT_STRAP_N")
	)
	(segment
		(start 344.393774 -32.58439)
		(end 344.420698 -32.58439)
		(width 0.12954)
		(layer "B.Cu")
		(net "FM_PCH_CONSENT_STRAP_N")
	)
	(segment
		(start 335.140046 -41.027096)
		(end 335.169002 -41.026842)
		(width 0.0889)
		(layer "B.Cu")
		(net "FM_PCH_CONSENT_STRAP_N")
	)
	(segment
		(start 339.7885 -35.690302)
		(end 341.251794 -34.227008)
		(width 0.12954)
		(layer "B.Cu")
		(net "FM_PCH_CONSENT_STRAP_N")
	)
	(segment
		(start 335.93405 -40.557196)
		(end 335.982818 -40.557196)
		(width 0.0889)
		(layer "B.Cu")
		(net "FM_PCH_CONSENT_STRAP_N")
	)
	(segment
		(start 345.92768 -28.022042)
		(end 344.420698 -29.529024)
		(width 0.12954)
		(layer "B.Cu")
		(net "FM_PCH_CONSENT_STRAP_N")
	)
	(segment
		(start 335.120488 -41.027096)
		(end 335.140046 -41.027096)
		(width 0.0889)
		(layer "B.Cu")
		(net "FM_PCH_CONSENT_STRAP_N")
	)
	(segment
		(start 336.73288 -39.99865)
		(end 336.913982 -39.99865)
		(width 0.12954)
		(layer "B.Cu")
		(net "FM_PCH_CONSENT_STRAP_N")
	)
	(segment
		(start 334.325468 -42.498772)
		(end 334.390238 -42.434002)
		(width 0.0889)
		(layer "B.Cu")
		(net "FM_PCH_CONSENT_STRAP_N")
	)
	(segment
		(start 346.80652 -20.036028)
		(end 345.92768 -20.914868)
		(width 0.12954)
		(layer "B.Cu")
		(net "FM_PCH_CONSENT_STRAP_N")
	)
	(segment
		(start 345.92768 -20.914868)
		(end 345.92768 -28.022042)
		(width 0.12954)
		(layer "B.Cu")
		(net "FM_PCH_CONSENT_STRAP_N")
	)
	(segment
		(start 341.894922 -34.227008)
		(end 343.314782 -32.807148)
		(width 0.12954)
		(layer "B.Cu")
		(net "FM_PCH_CONSENT_STRAP_N")
	)
	(segment
		(start 351.1677 -20.036028)
		(end 346.80652 -20.036028)
		(width 0.12954)
		(layer "B.Cu")
		(net "FM_PCH_CONSENT_STRAP_N")
	)
	(segment
		(start 334.325468 -42.811446)
		(end 334.325468 -42.498772)
		(width 0.0889)
		(layer "B.Cu")
		(net "FM_PCH_CONSENT_STRAP_N")
	)
	(segment
		(start 341.251794 -34.227008)
		(end 341.894922 -34.227008)
		(width 0.12954)
		(layer "B.Cu")
		(net "FM_PCH_CONSENT_STRAP_N")
	)
	(segment
		(start 353.8855 -22.753828)
		(end 351.1677 -20.036028)
		(width 0.12954)
		(layer "B.Cu")
		(net "FM_PCH_CONSENT_STRAP_N")
	)
	(segment
		(start 353.8855 -23.825708)
		(end 353.8855 -22.753828)
		(width 0.12954)
		(layer "B.Cu")
		(net "FM_PCH_CONSENT_STRAP_N")
	)
	(segment
		(start 336.443828 -40.274748)
		(end 336.456782 -40.274748)
		(width 0.0889)
		(layer "B.Cu")
		(net "FM_PCH_CONSENT_STRAP_N")
	)
	(segment
		(start 336.627216 -40.104314)
		(end 336.73288 -39.99865)
		(width 0.12954)
		(layer "B.Cu")
		(net "FM_PCH_CONSENT_STRAP_N")
	)
	(segment
		(start 344.420698 -29.529024)
		(end 344.420698 -31.527242)
		(width 0.12954)
		(layer "B.Cu")
		(net "FM_PCH_CONSENT_STRAP_N")
	)
	(segment
		(start 343.314782 -32.807148)
		(end 344.171016 -32.807148)
		(width 0.12954)
		(layer "B.Cu")
		(net "FM_PCH_CONSENT_STRAP_N")
	)
	(segment
		(start 336.456782 -40.274748)
		(end 336.627216 -40.104314)
		(width 0.0889)
		(layer "B.Cu")
		(net "FM_PCH_CONSENT_STRAP_N")
	)
	(segment
		(start 336.913982 -39.99865)
		(end 339.7885 -37.124132)
		(width 0.12954)
		(layer "B.Cu")
		(net "FM_PCH_CONSENT_STRAP_N")
	)
	(segment
		(start 344.171016 -32.807148)
		(end 344.393774 -32.58439)
		(width 0.12954)
		(layer "B.Cu")
		(net "FM_PCH_CONSENT_STRAP_N")
	)
	(segment
		(start 339.7885 -37.124132)
		(end 339.7885 -35.690302)
		(width 0.12954)
		(layer "B.Cu")
		(net "FM_PCH_CONSENT_STRAP_N")
	)
	(segment
		(start 344.420698 -32.58439)
		(end 344.420698 -31.527242)
		(width 0.12954)
		(layer "B.Cu")
		(net "FM_PCH_CONSENT_STRAP_N")
	)
	(arc
		(start 334.390238 -42.434002)
		(mid 334.636216 -42.344753)
		(end 334.815688 -42.154348)
		(width 0.0889)
		(layer "B.Cu")
		(net "FM_PCH_CONSENT_STRAP_N")
	)
	(arc
		(start 334.815688 -42.154348)
		(mid 334.891362 -41.871646)
		(end 334.815688 -41.588944)
		(width 0.0889)
		(layer "B.Cu")
		(net "FM_PCH_CONSENT_STRAP_N")
	)
	(arc
		(start 334.815688 -41.214548)
		(mid 334.944307 -41.082163)
		(end 335.120488 -41.027096)
		(width 0.0889)
		(layer "B.Cu")
		(net "FM_PCH_CONSENT_STRAP_N")
	)
	(arc
		(start 334.815688 -41.588944)
		(mid 334.765647 -41.401746)
		(end 334.815688 -41.214548)
		(width 0.0889)
		(layer "B.Cu")
		(net "FM_PCH_CONSENT_STRAP_N")
	)
	(arc
		(start 335.169002 -41.026842)
		(mid 335.434548 -40.94403)
		(end 335.628488 -40.744648)
		(width 0.0889)
		(layer "B.Cu")
		(net "FM_PCH_CONSENT_STRAP_N")
	)
	(arc
		(start 335.982818 -40.557196)
		(mid 336.249239 -40.474591)
		(end 336.443828 -40.274748)
		(width 0.0889)
		(layer "B.Cu")
		(net "FM_PCH_CONSENT_STRAP_N")
	)
	(arc
		(start 335.628488 -40.744648)
		(mid 335.757431 -40.612064)
		(end 335.93405 -40.557196)
		(width 0.0889)
		(layer "B.Cu")
		(net "FM_PCH_CONSENT_STRAP_N")
	)
	(segment
		(start 384.15468 -46.731428)
		(end 361.24896 -23.825708)
		(width 0.127)
		(layer "In2.Cu")
		(net "FM_PCH_CONSENT_STRAP_N")
	)
	(segment
		(start 384.15468 -60.735464)
		(end 384.15468 -46.731428)
		(width 0.127)
		(layer "In2.Cu")
		(net "FM_PCH_CONSENT_STRAP_N")
	)
	(segment
		(start 361.24896 -23.825708)
		(end 353.8855 -23.825708)
		(width 0.127)
		(layer "In2.Cu")
		(net "FM_PCH_CONSENT_STRAP_N")
	)
	(segment
		(start 326.584818 -50.951384)
		(end 326.231758 -50.951384)
		(width 0.0889)
		(layer "F.Cu")
		(net "FM_PCH_BOOT_BIOS_STRAP")
	)
	(segment
		(start 315.522102 -53.214778)
		(end 317.223902 -53.214778)
		(width 0.12954)
		(layer "F.Cu")
		(net "FM_PCH_BOOT_BIOS_STRAP")
	)
	(segment
		(start 317.223902 -53.214778)
		(end 317.796672 -53.787548)
		(width 0.12954)
		(layer "F.Cu")
		(net "FM_PCH_BOOT_BIOS_STRAP")
	)
	(segment
		(start 322.087494 -52.385468)
		(end 320.96202 -52.385468)
		(width 0.12954)
		(layer "F.Cu")
		(net "FM_PCH_BOOT_BIOS_STRAP")
	)
	(segment
		(start 318.062864 -53.11394)
		(end 318.062864 -53.521356)
		(width 0.12954)
		(layer "F.Cu")
		(net "FM_PCH_BOOT_BIOS_STRAP")
	)
	(segment
		(start 322.920614 -51.552348)
		(end 322.804282 -51.66868)
		(width 0.0889)
		(layer "F.Cu")
		(net "FM_PCH_BOOT_BIOS_STRAP")
	)
	(segment
		(start 320.597022 -52.750466)
		(end 318.426338 -52.750466)
		(width 0.12954)
		(layer "F.Cu")
		(net "FM_PCH_BOOT_BIOS_STRAP")
	)
	(segment
		(start 325.1581 -51.552348)
		(end 322.920614 -51.552348)
		(width 0.0889)
		(layer "F.Cu")
		(net "FM_PCH_BOOT_BIOS_STRAP")
	)
	(segment
		(start 322.804282 -51.66868)
		(end 322.087494 -52.385468)
		(width 0.12954)
		(layer "F.Cu")
		(net "FM_PCH_BOOT_BIOS_STRAP")
	)
	(segment
		(start 315.510672 -53.203348)
		(end 315.522102 -53.214778)
		(width 0.12954)
		(layer "F.Cu")
		(net "FM_PCH_BOOT_BIOS_STRAP")
	)
	(segment
		(start 326.182482 -50.902108)
		(end 325.80834 -50.902108)
		(width 0.0889)
		(layer "F.Cu")
		(net "FM_PCH_BOOT_BIOS_STRAP")
	)
	(segment
		(start 320.6242 -52.723288)
		(end 320.597022 -52.750466)
		(width 0.12954)
		(layer "F.Cu")
		(net "FM_PCH_BOOT_BIOS_STRAP")
	)
	(segment
		(start 325.80834 -50.902108)
		(end 325.1581 -51.552348)
		(width 0.0889)
		(layer "F.Cu")
		(net "FM_PCH_BOOT_BIOS_STRAP")
	)
	(segment
		(start 318.062864 -53.521356)
		(end 317.796672 -53.787548)
		(width 0.12954)
		(layer "F.Cu")
		(net "FM_PCH_BOOT_BIOS_STRAP")
	)
	(segment
		(start 318.426338 -52.750466)
		(end 318.062864 -53.11394)
		(width 0.12954)
		(layer "F.Cu")
		(net "FM_PCH_BOOT_BIOS_STRAP")
	)
	(segment
		(start 320.96202 -52.385468)
		(end 320.6242 -52.723288)
		(width 0.12954)
		(layer "F.Cu")
		(net "FM_PCH_BOOT_BIOS_STRAP")
	)
	(segment
		(start 326.231758 -50.951384)
		(end 326.182482 -50.902108)
		(width 0.0889)
		(layer "F.Cu")
		(net "FM_PCH_BOOT_BIOS_STRAP")
	)
	(via
		(at 320.6242 -52.723288)
		(size 0.762)
		(drill 0.381)
		(layers "F.Cu" "B.Cu")
		(net "FM_PCH_BOOT_BIOS_STRAP")
	)
	(segment
		(start 195.537074 -110.065058)
		(end 192.611756 -110.065058)
		(width 0.12954)
		(layer "F.Cu")
		(net "FM_PCH_BMC_THERMTRIP_N")
	)
	(segment
		(start 199.88022 -110.607348)
		(end 199.0217 -110.607348)
		(width 0.12954)
		(layer "F.Cu")
		(net "FM_PCH_BMC_THERMTRIP_N")
	)
	(segment
		(start 195.866004 -109.736128)
		(end 195.537074 -110.065058)
		(width 0.12954)
		(layer "F.Cu")
		(net "FM_PCH_BMC_THERMTRIP_N")
	)
	(segment
		(start 314.117736 -52.288948)
		(end 314.710572 -52.288948)
		(width 0.12954)
		(layer "F.Cu")
		(net "FM_PCH_BMC_THERMTRIP_N")
	)
	(segment
		(start 203.29779 -110.11154)
		(end 201.260456 -110.11154)
		(width 0.12954)
		(layer "F.Cu")
		(net "FM_PCH_BMC_THERMTRIP_N")
	)
	(segment
		(start 200.866502 -110.108238)
		(end 200.8632 -110.11154)
		(width 0.12954)
		(layer "F.Cu")
		(net "FM_PCH_BMC_THERMTRIP_N")
	)
	(segment
		(start 198.12254 -110.244128)
		(end 197.61454 -109.736128)
		(width 0.12954)
		(layer "F.Cu")
		(net "FM_PCH_BMC_THERMTRIP_N")
	)
	(segment
		(start 197.61454 -109.736128)
		(end 195.866004 -109.736128)
		(width 0.12954)
		(layer "F.Cu")
		(net "FM_PCH_BMC_THERMTRIP_N")
	)
	(segment
		(start 203.99248 -108.905548)
		(end 203.99248 -109.41685)
		(width 0.12954)
		(layer "F.Cu")
		(net "FM_PCH_BMC_THERMTRIP_N")
	)
	(segment
		(start 200.8632 -110.11154)
		(end 200.376028 -110.11154)
		(width 0.12954)
		(layer "F.Cu")
		(net "FM_PCH_BMC_THERMTRIP_N")
	)
	(segment
		(start 199.0217 -110.607348)
		(end 198.65848 -110.244128)
		(width 0.12954)
		(layer "F.Cu")
		(net "FM_PCH_BMC_THERMTRIP_N")
	)
	(segment
		(start 198.65848 -110.244128)
		(end 198.12254 -110.244128)
		(width 0.12954)
		(layer "F.Cu")
		(net "FM_PCH_BMC_THERMTRIP_N")
	)
	(segment
		(start 200.376028 -110.11154)
		(end 199.88022 -110.607348)
		(width 0.12954)
		(layer "F.Cu")
		(net "FM_PCH_BMC_THERMTRIP_N")
	)
	(segment
		(start 314.092336 -52.263548)
		(end 314.117736 -52.288948)
		(width 0.12954)
		(layer "F.Cu")
		(net "FM_PCH_BMC_THERMTRIP_N")
	)
	(segment
		(start 192.611756 -110.065058)
		(end 191.398906 -111.277908)
		(width 0.12954)
		(layer "F.Cu")
		(net "FM_PCH_BMC_THERMTRIP_N")
	)
	(segment
		(start 191.398906 -111.277908)
		(end 188.0489 -111.277908)
		(width 0.12954)
		(layer "F.Cu")
		(net "FM_PCH_BMC_THERMTRIP_N")
	)
	(segment
		(start 188.0489 -111.277908)
		(end 187.346336 -110.575344)
		(width 0.12954)
		(layer "F.Cu")
		(net "FM_PCH_BMC_THERMTRIP_N")
	)
	(segment
		(start 201.257154 -110.108238)
		(end 200.866502 -110.108238)
		(width 0.12954)
		(layer "F.Cu")
		(net "FM_PCH_BMC_THERMTRIP_N")
	)
	(segment
		(start 201.260456 -110.11154)
		(end 201.257154 -110.108238)
		(width 0.12954)
		(layer "F.Cu")
		(net "FM_PCH_BMC_THERMTRIP_N")
	)
	(segment
		(start 203.99248 -109.41685)
		(end 203.29779 -110.11154)
		(width 0.12954)
		(layer "F.Cu")
		(net "FM_PCH_BMC_THERMTRIP_N")
	)
	(segment
		(start 187.346336 -110.575344)
		(end 186.955684 -110.575344)
		(width 0.12954)
		(layer "F.Cu")
		(net "FM_PCH_BMC_THERMTRIP_N")
	)
	(via
		(at 203.99248 -108.905548)
		(size 0.508)
		(drill 0.254)
		(layers "F.Cu" "B.Cu")
		(net "FM_PCH_BMC_THERMTRIP_N")
	)
	(via
		(at 314.092336 -52.263548)
		(size 0.508)
		(drill 0.254)
		(layers "F.Cu" "B.Cu")
		(net "FM_PCH_BMC_THERMTRIP_N")
	)
	(via
		(at 204.03312 -90.165428)
		(size 0.508)
		(drill 0.254)
		(layers "F.Cu" "B.Cu")
		(net "FM_PCH_BMC_THERMTRIP_N")
	)
	(segment
		(start 204.03312 -90.165428)
		(end 204.03312 -90.44432)
		(width 0.127)
		(layer "In2.Cu")
		(net "FM_PCH_BMC_THERMTRIP_N")
	)
	(segment
		(start 204.9018 -108.905548)
		(end 203.99248 -108.905548)
		(width 0.127)
		(layer "In2.Cu")
		(net "FM_PCH_BMC_THERMTRIP_N")
	)
	(segment
		(start 208.69148 -105.115868)
		(end 204.9018 -108.905548)
		(width 0.127)
		(layer "In2.Cu")
		(net "FM_PCH_BMC_THERMTRIP_N")
	)
	(segment
		(start 204.2922 -90.7034)
		(end 205.7654 -90.7034)
		(width 0.127)
		(layer "In2.Cu")
		(net "FM_PCH_BMC_THERMTRIP_N")
	)
	(segment
		(start 206.7179 -91.6559)
		(end 206.7179 -93.4085)
		(width 0.127)
		(layer "In2.Cu")
		(net "FM_PCH_BMC_THERMTRIP_N")
	)
	(segment
		(start 206.7179 -93.4085)
		(end 208.69148 -95.38208)
		(width 0.127)
		(layer "In2.Cu")
		(net "FM_PCH_BMC_THERMTRIP_N")
	)
	(segment
		(start 204.03312 -90.44432)
		(end 204.2922 -90.7034)
		(width 0.127)
		(layer "In2.Cu")
		(net "FM_PCH_BMC_THERMTRIP_N")
	)
	(segment
		(start 205.7654 -90.7034)
		(end 206.7179 -91.6559)
		(width 0.127)
		(layer "In2.Cu")
		(net "FM_PCH_BMC_THERMTRIP_N")
	)
	(segment
		(start 208.69148 -95.38208)
		(end 208.69148 -105.115868)
		(width 0.127)
		(layer "In2.Cu")
		(net "FM_PCH_BMC_THERMTRIP_N")
	)
	(segment
		(start 312.23204 -59.162188)
		(end 312.23204 -53.165248)
		(width 0.127)
		(layer "In11.Cu")
		(net "FM_PCH_BMC_THERMTRIP_N")
	)
	(segment
		(start 215.065864 -88.274144)
		(end 231.84866 -71.491348)
		(width 0.127)
		(layer "In11.Cu")
		(net "FM_PCH_BMC_THERMTRIP_N")
	)
	(segment
		(start 303.05248 -63.033148)
		(end 306.07508 -60.010548)
		(width 0.127)
		(layer "In11.Cu")
		(net "FM_PCH_BMC_THERMTRIP_N")
	)
	(segment
		(start 240.5761 -71.491348)
		(end 250.344686 -81.259934)
		(width 0.127)
		(layer "In11.Cu")
		(net "FM_PCH_BMC_THERMTRIP_N")
	)
	(segment
		(start 297.639232 -81.259934)
		(end 303.05248 -75.846686)
		(width 0.127)
		(layer "In11.Cu")
		(net "FM_PCH_BMC_THERMTRIP_N")
	)
	(segment
		(start 312.23204 -53.165248)
		(end 313.13374 -52.263548)
		(width 0.127)
		(layer "In11.Cu")
		(net "FM_PCH_BMC_THERMTRIP_N")
	)
	(segment
		(start 311.38368 -60.010548)
		(end 312.23204 -59.162188)
		(width 0.127)
		(layer "In11.Cu")
		(net "FM_PCH_BMC_THERMTRIP_N")
	)
	(segment
		(start 303.05248 -75.846686)
		(end 303.05248 -63.033148)
		(width 0.127)
		(layer "In11.Cu")
		(net "FM_PCH_BMC_THERMTRIP_N")
	)
	(segment
		(start 306.07508 -60.010548)
		(end 311.38368 -60.010548)
		(width 0.127)
		(layer "In11.Cu")
		(net "FM_PCH_BMC_THERMTRIP_N")
	)
	(segment
		(start 313.13374 -52.263548)
		(end 314.092336 -52.263548)
		(width 0.127)
		(layer "In11.Cu")
		(net "FM_PCH_BMC_THERMTRIP_N")
	)
	(segment
		(start 231.84866 -71.491348)
		(end 240.5761 -71.491348)
		(width 0.127)
		(layer "In11.Cu")
		(net "FM_PCH_BMC_THERMTRIP_N")
	)
	(segment
		(start 204.03312 -88.896952)
		(end 204.655928 -88.274144)
		(width 0.127)
		(layer "In11.Cu")
		(net "FM_PCH_BMC_THERMTRIP_N")
	)
	(segment
		(start 204.03312 -90.165428)
		(end 204.03312 -88.896952)
		(width 0.127)
		(layer "In11.Cu")
		(net "FM_PCH_BMC_THERMTRIP_N")
	)
	(segment
		(start 250.344686 -81.259934)
		(end 297.639232 -81.259934)
		(width 0.127)
		(layer "In11.Cu")
		(net "FM_PCH_BMC_THERMTRIP_N")
	)
	(segment
		(start 204.655928 -88.274144)
		(end 215.065864 -88.274144)
		(width 0.127)
		(layer "In11.Cu")
		(net "FM_PCH_BMC_THERMTRIP_N")
	)
	(segment
		(start 328.624692 -52.281582)
		(end 328.797666 -52.580794)
		(width 0.12954)
		(layer "F.Cu")
		(net "FM_PCH_BIOS_RCVR_MODE")
	)
	(segment
		(start 328.797666 -52.580794)
		(end 329.165966 -52.679346)
		(width 0.12954)
		(layer "F.Cu")
		(net "FM_PCH_BIOS_RCVR_MODE")
	)
	(segment
		(start 307.54193 -50.878486)
		(end 308.28488 -50.878486)
		(width 0.12954)
		(layer "F.Cu")
		(net "FM_PCH_BIOS_RCVR_MODE")
	)
	(via
		(at 328.624692 -52.281582)
		(size 0.4572)
		(drill 0.2032)
		(layers "F.Cu" "B.Cu")
		(net "FM_PCH_BIOS_RCVR_MODE")
	)
	(via
		(at 308.28488 -50.878486)
		(size 0.508)
		(drill 0.254)
		(layers "F.Cu" "B.Cu")
		(net "FM_PCH_BIOS_RCVR_MODE")
	)
	(segment
		(start 316.20968 -50.383948)
		(end 314.82284 -51.770788)
		(width 0.127)
		(layer "In6.Cu")
		(net "FM_PCH_BIOS_RCVR_MODE")
	)
	(segment
		(start 313.43854 -52.085748)
		(end 311.63768 -52.085748)
		(width 0.127)
		(layer "In6.Cu")
		(net "FM_PCH_BIOS_RCVR_MODE")
	)
	(segment
		(start 324.663816 -51.7906)
		(end 324.152768 -51.279552)
		(width 0.127)
		(layer "In6.Cu")
		(net "FM_PCH_BIOS_RCVR_MODE")
	)
	(segment
		(start 310.430418 -50.878486)
		(end 308.28488 -50.878486)
		(width 0.127)
		(layer "In6.Cu")
		(net "FM_PCH_BIOS_RCVR_MODE")
	)
	(segment
		(start 313.7535 -51.770788)
		(end 313.43854 -52.085748)
		(width 0.127)
		(layer "In6.Cu")
		(net "FM_PCH_BIOS_RCVR_MODE")
	)
	(segment
		(start 311.63768 -52.085748)
		(end 310.430418 -50.878486)
		(width 0.127)
		(layer "In6.Cu")
		(net "FM_PCH_BIOS_RCVR_MODE")
	)
	(segment
		(start 328.13371 -51.7906)
		(end 324.663816 -51.7906)
		(width 0.127)
		(layer "In6.Cu")
		(net "FM_PCH_BIOS_RCVR_MODE")
	)
	(segment
		(start 324.152768 -51.279552)
		(end 322.896484 -51.279552)
		(width 0.127)
		(layer "In6.Cu")
		(net "FM_PCH_BIOS_RCVR_MODE")
	)
	(segment
		(start 322.896484 -51.279552)
		(end 322.00088 -50.383948)
		(width 0.127)
		(layer "In6.Cu")
		(net "FM_PCH_BIOS_RCVR_MODE")
	)
	(segment
		(start 322.00088 -50.383948)
		(end 316.20968 -50.383948)
		(width 0.127)
		(layer "In6.Cu")
		(net "FM_PCH_BIOS_RCVR_MODE")
	)
	(segment
		(start 328.624692 -52.281582)
		(end 328.13371 -51.7906)
		(width 0.127)
		(layer "In6.Cu")
		(net "FM_PCH_BIOS_RCVR_MODE")
	)
	(segment
		(start 314.82284 -51.770788)
		(end 313.7535 -51.770788)
		(width 0.127)
		(layer "In6.Cu")
		(net "FM_PCH_BIOS_RCVR_MODE")
	)
	(segment
		(start 367.410746 -56.09844)
		(end 367.410746 -58.064146)
		(width 0.127)
		(layer "In15.Cu")
		(net "FM_PCH_BIOS_RCVR_MODE")
	)
	(segment
		(start 301.2694 -56.937148)
		(end 299.72 -56.937148)
		(width 0.127)
		(layer "In15.Cu")
		(net "FM_PCH_BIOS_RCVR_MODE")
	)
	(segment
		(start 306.183792 -50.878486)
		(end 308.28488 -50.878486)
		(width 0.127)
		(layer "In15.Cu")
		(net "FM_PCH_BIOS_RCVR_MODE")
	)
	(segment
		(start 429.16983 -42.079926)
		(end 427.779688 -43.470068)
		(width 0.127)
		(layer "In15.Cu")
		(net "FM_PCH_BIOS_RCVR_MODE")
	)
	(segment
		(start 427.779688 -43.470068)
		(end 397.38554 -43.470068)
		(width 0.127)
		(layer "In15.Cu")
		(net "FM_PCH_BIOS_RCVR_MODE")
	)
	(segment
		(start 365.626904 -54.314598)
		(end 367.410746 -56.09844)
		(width 0.127)
		(layer "In15.Cu")
		(net "FM_PCH_BIOS_RCVR_MODE")
	)
	(segment
		(start 371.74297 -51.190398)
		(end 366.643666 -51.190398)
		(width 0.127)
		(layer "In15.Cu")
		(net "FM_PCH_BIOS_RCVR_MODE")
	)
	(segment
		(start 345.256358 -58.410348)
		(end 328.69378 -58.410348)
		(width 0.127)
		(layer "In15.Cu")
		(net "FM_PCH_BIOS_RCVR_MODE")
	)
	(segment
		(start 303.52746 -57.988708)
		(end 302.1965 -56.657748)
		(width 0.127)
		(layer "In15.Cu")
		(net "FM_PCH_BIOS_RCVR_MODE")
	)
	(segment
		(start 365.626904 -52.20716)
		(end 365.626904 -54.314598)
		(width 0.127)
		(layer "In15.Cu")
		(net "FM_PCH_BIOS_RCVR_MODE")
	)
	(segment
		(start 299.61332 -50.020728)
		(end 305.326034 -50.020728)
		(width 0.127)
		(layer "In15.Cu")
		(net "FM_PCH_BIOS_RCVR_MODE")
	)
	(segment
		(start 345.916758 -57.749948)
		(end 345.256358 -58.410348)
		(width 0.127)
		(layer "In15.Cu")
		(net "FM_PCH_BIOS_RCVR_MODE")
	)
	(segment
		(start 301.5488 -56.657748)
		(end 301.2694 -56.937148)
		(width 0.127)
		(layer "In15.Cu")
		(net "FM_PCH_BIOS_RCVR_MODE")
	)
	(segment
		(start 365.77524 -59.699652)
		(end 363.624876 -59.699652)
		(width 0.127)
		(layer "In15.Cu")
		(net "FM_PCH_BIOS_RCVR_MODE")
	)
	(segment
		(start 347.741494 -58.908696)
		(end 346.582746 -57.749948)
		(width 0.127)
		(layer "In15.Cu")
		(net "FM_PCH_BIOS_RCVR_MODE")
	)
	(segment
		(start 366.643666 -51.190398)
		(end 365.626904 -52.20716)
		(width 0.127)
		(layer "In15.Cu")
		(net "FM_PCH_BIOS_RCVR_MODE")
	)
	(segment
		(start 323.22516 -56.746648)
		(end 316.9793 -56.746648)
		(width 0.127)
		(layer "In15.Cu")
		(net "FM_PCH_BIOS_RCVR_MODE")
	)
	(segment
		(start 325.78802 -55.504588)
		(end 324.46722 -55.504588)
		(width 0.127)
		(layer "In15.Cu")
		(net "FM_PCH_BIOS_RCVR_MODE")
	)
	(segment
		(start 363.624876 -59.699652)
		(end 363.31144 -60.013088)
		(width 0.127)
		(layer "In15.Cu")
		(net "FM_PCH_BIOS_RCVR_MODE")
	)
	(segment
		(start 298.82846 -56.045608)
		(end 298.82846 -50.805588)
		(width 0.127)
		(layer "In15.Cu")
		(net "FM_PCH_BIOS_RCVR_MODE")
	)
	(segment
		(start 375.96572 -46.967648)
		(end 371.74297 -51.190398)
		(width 0.127)
		(layer "In15.Cu")
		(net "FM_PCH_BIOS_RCVR_MODE")
	)
	(segment
		(start 354.03536 -60.013088)
		(end 352.930968 -58.908696)
		(width 0.127)
		(layer "In15.Cu")
		(net "FM_PCH_BIOS_RCVR_MODE")
	)
	(segment
		(start 305.326034 -50.020728)
		(end 306.183792 -50.878486)
		(width 0.127)
		(layer "In15.Cu")
		(net "FM_PCH_BIOS_RCVR_MODE")
	)
	(segment
		(start 316.9793 -56.746648)
		(end 316.57798 -56.345328)
		(width 0.127)
		(layer "In15.Cu")
		(net "FM_PCH_BIOS_RCVR_MODE")
	)
	(segment
		(start 367.410746 -58.064146)
		(end 365.77524 -59.699652)
		(width 0.127)
		(layer "In15.Cu")
		(net "FM_PCH_BIOS_RCVR_MODE")
	)
	(segment
		(start 316.57798 -56.345328)
		(end 316.15888 -56.345328)
		(width 0.127)
		(layer "In15.Cu")
		(net "FM_PCH_BIOS_RCVR_MODE")
	)
	(segment
		(start 298.82846 -50.805588)
		(end 299.61332 -50.020728)
		(width 0.127)
		(layer "In15.Cu")
		(net "FM_PCH_BIOS_RCVR_MODE")
	)
	(segment
		(start 397.38554 -43.470068)
		(end 393.88796 -46.967648)
		(width 0.127)
		(layer "In15.Cu")
		(net "FM_PCH_BIOS_RCVR_MODE")
	)
	(segment
		(start 316.15888 -56.345328)
		(end 314.5155 -57.988708)
		(width 0.127)
		(layer "In15.Cu")
		(net "FM_PCH_BIOS_RCVR_MODE")
	)
	(segment
		(start 302.1965 -56.657748)
		(end 301.5488 -56.657748)
		(width 0.127)
		(layer "In15.Cu")
		(net "FM_PCH_BIOS_RCVR_MODE")
	)
	(segment
		(start 429.170084 -42.079926)
		(end 429.16983 -42.079926)
		(width 0.127)
		(layer "In15.Cu")
		(net "FM_PCH_BIOS_RCVR_MODE")
	)
	(segment
		(start 299.72 -56.937148)
		(end 298.82846 -56.045608)
		(width 0.127)
		(layer "In15.Cu")
		(net "FM_PCH_BIOS_RCVR_MODE")
	)
	(segment
		(start 363.31144 -60.013088)
		(end 354.03536 -60.013088)
		(width 0.127)
		(layer "In15.Cu")
		(net "FM_PCH_BIOS_RCVR_MODE")
	)
	(segment
		(start 352.930968 -58.908696)
		(end 347.741494 -58.908696)
		(width 0.127)
		(layer "In15.Cu")
		(net "FM_PCH_BIOS_RCVR_MODE")
	)
	(segment
		(start 324.46722 -55.504588)
		(end 323.22516 -56.746648)
		(width 0.127)
		(layer "In15.Cu")
		(net "FM_PCH_BIOS_RCVR_MODE")
	)
	(segment
		(start 314.5155 -57.988708)
		(end 303.52746 -57.988708)
		(width 0.127)
		(layer "In15.Cu")
		(net "FM_PCH_BIOS_RCVR_MODE")
	)
	(segment
		(start 393.88796 -46.967648)
		(end 375.96572 -46.967648)
		(width 0.127)
		(layer "In15.Cu")
		(net "FM_PCH_BIOS_RCVR_MODE")
	)
	(segment
		(start 346.582746 -57.749948)
		(end 345.916758 -57.749948)
		(width 0.127)
		(layer "In15.Cu")
		(net "FM_PCH_BIOS_RCVR_MODE")
	)
	(segment
		(start 328.69378 -58.410348)
		(end 325.78802 -55.504588)
		(width 0.127)
		(layer "In15.Cu")
		(net "FM_PCH_BIOS_RCVR_MODE")
	)
	(segment
		(start 203.4286 -122.4026)
		(end 217.622628 -122.4026)
		(width 0.12954)
		(layer "F.Cu")
		(net "FM_PCHHOT_R_N")
	)
	(segment
		(start 186.955684 -117.775482)
		(end 187.940188 -117.775482)
		(width 0.12954)
		(layer "F.Cu")
		(net "FM_PCHHOT_R_N")
	)
	(segment
		(start 305.138582 -43.589194)
		(end 307.325776 -43.589194)
		(width 0.12954)
		(layer "F.Cu")
		(net "FM_PCHHOT_R_N")
	)
	(segment
		(start 217.622628 -122.4026)
		(end 225.933 -114.092228)
		(width 0.12954)
		(layer "F.Cu")
		(net "FM_PCHHOT_R_N")
	)
	(segment
		(start 304.948336 -43.398948)
		(end 305.138582 -43.589194)
		(width 0.12954)
		(layer "F.Cu")
		(net "FM_PCHHOT_R_N")
	)
	(segment
		(start 189.509654 -119.344948)
		(end 190.78448 -119.344948)
		(width 0.12954)
		(layer "F.Cu")
		(net "FM_PCHHOT_R_N")
	)
	(segment
		(start 202.270868 -121.244868)
		(end 203.4286 -122.4026)
		(width 0.12954)
		(layer "F.Cu")
		(net "FM_PCHHOT_R_N")
	)
	(segment
		(start 225.933 -114.092228)
		(end 295.25976 -114.092228)
		(width 0.12954)
		(layer "F.Cu")
		(net "FM_PCHHOT_R_N")
	)
	(segment
		(start 302.51908 -43.398948)
		(end 304.948336 -43.398948)
		(width 0.12954)
		(layer "F.Cu")
		(net "FM_PCHHOT_R_N")
	)
	(segment
		(start 190.78448 -119.344948)
		(end 192.6844 -121.244868)
		(width 0.12954)
		(layer "F.Cu")
		(net "FM_PCHHOT_R_N")
	)
	(segment
		(start 192.6844 -121.244868)
		(end 202.270868 -121.244868)
		(width 0.12954)
		(layer "F.Cu")
		(net "FM_PCHHOT_R_N")
	)
	(segment
		(start 295.25976 -114.092228)
		(end 295.73728 -114.569748)
		(width 0.12954)
		(layer "F.Cu")
		(net "FM_PCHHOT_R_N")
	)
	(segment
		(start 187.940188 -117.775482)
		(end 189.509654 -119.344948)
		(width 0.12954)
		(layer "F.Cu")
		(net "FM_PCHHOT_R_N")
	)
	(via
		(at 295.73728 -114.569748)
		(size 0.508)
		(drill 0.254)
		(layers "F.Cu" "B.Cu")
		(net "FM_PCHHOT_R_N")
	)
	(via
		(at 302.51908 -43.398948)
		(size 0.508)
		(drill 0.254)
		(layers "F.Cu" "B.Cu")
		(net "FM_PCHHOT_R_N")
	)
	(segment
		(start 302.4124 -74.000868)
		(end 300.662848 -75.75042)
		(width 0.127)
		(layer "In2.Cu")
		(net "FM_PCHHOT_R_N")
	)
	(segment
		(start 300.662848 -75.75042)
		(end 300.662848 -79.54264)
		(width 0.127)
		(layer "In2.Cu")
		(net "FM_PCHHOT_R_N")
	)
	(segment
		(start 302.4124 -43.505628)
		(end 302.4124 -74.000868)
		(width 0.127)
		(layer "In2.Cu")
		(net "FM_PCHHOT_R_N")
	)
	(segment
		(start 302.51908 -43.398948)
		(end 302.4124 -43.505628)
		(width 0.127)
		(layer "In2.Cu")
		(net "FM_PCHHOT_R_N")
	)
	(segment
		(start 295.73728 -84.468208)
		(end 295.73728 -114.569748)
		(width 0.127)
		(layer "In2.Cu")
		(net "FM_PCHHOT_R_N")
	)
	(segment
		(start 300.662848 -79.54264)
		(end 295.73728 -84.468208)
		(width 0.127)
		(layer "In2.Cu")
		(net "FM_PCHHOT_R_N")
	)
	(segment
		(start 308.125876 -43.589194)
		(end 308.386988 -43.589194)
		(width 0.12954)
		(layer "F.Cu")
		(net "FM_PCHHOT_N")
	)
	(segment
		(start 317.355982 -44.03725)
		(end 318.16929 -44.850558)
		(width 0.12954)
		(layer "F.Cu")
		(net "FM_PCHHOT_N")
	)
	(segment
		(start 318.984376 -46.180502)
		(end 322.575174 -46.180502)
		(width 0.12954)
		(layer "F.Cu")
		(net "FM_PCHHOT_N")
	)
	(segment
		(start 309.119016 -43.634152)
		(end 309.353966 -43.399202)
		(width 0.12954)
		(layer "F.Cu")
		(net "FM_PCHHOT_N")
	)
	(segment
		(start 310.196484 -43.399202)
		(end 310.76773 -43.970448)
		(width 0.12954)
		(layer "F.Cu")
		(net "FM_PCHHOT_N")
	)
	(segment
		(start 318.16929 -45.365416)
		(end 318.984376 -46.180502)
		(width 0.12954)
		(layer "F.Cu")
		(net "FM_PCHHOT_N")
	)
	(segment
		(start 309.119016 -43.92803)
		(end 309.119016 -43.634152)
		(width 0.12954)
		(layer "F.Cu")
		(net "FM_PCHHOT_N")
	)
	(segment
		(start 323.276468 -46.180502)
		(end 323.619622 -45.837348)
		(width 0.0889)
		(layer "F.Cu")
		(net "FM_PCHHOT_N")
	)
	(segment
		(start 309.353966 -43.399202)
		(end 310.196484 -43.399202)
		(width 0.12954)
		(layer "F.Cu")
		(net "FM_PCHHOT_N")
	)
	(segment
		(start 313.939682 -44.526708)
		(end 314.42914 -44.03725)
		(width 0.12954)
		(layer "F.Cu")
		(net "FM_PCHHOT_N")
	)
	(segment
		(start 310.76773 -43.970448)
		(end 310.76773 -44.112688)
		(width 0.12954)
		(layer "F.Cu")
		(net "FM_PCHHOT_N")
	)
	(segment
		(start 308.386988 -43.589194)
		(end 308.725824 -43.92803)
		(width 0.12954)
		(layer "F.Cu")
		(net "FM_PCHHOT_N")
	)
	(segment
		(start 325.039736 -45.837348)
		(end 325.651622 -46.449234)
		(width 0.0889)
		(layer "F.Cu")
		(net "FM_PCHHOT_N")
	)
	(segment
		(start 314.42914 -44.03725)
		(end 317.355982 -44.03725)
		(width 0.12954)
		(layer "F.Cu")
		(net "FM_PCHHOT_N")
	)
	(segment
		(start 318.16929 -44.850558)
		(end 318.16929 -45.365416)
		(width 0.12954)
		(layer "F.Cu")
		(net "FM_PCHHOT_N")
	)
	(segment
		(start 322.575174 -46.180502)
		(end 323.276468 -46.180502)
		(width 0.0889)
		(layer "F.Cu")
		(net "FM_PCHHOT_N")
	)
	(segment
		(start 310.76773 -44.112688)
		(end 311.18175 -44.526708)
		(width 0.12954)
		(layer "F.Cu")
		(net "FM_PCHHOT_N")
	)
	(segment
		(start 308.725824 -43.92803)
		(end 309.119016 -43.92803)
		(width 0.12954)
		(layer "F.Cu")
		(net "FM_PCHHOT_N")
	)
	(segment
		(start 323.619622 -45.837348)
		(end 325.039736 -45.837348)
		(width 0.0889)
		(layer "F.Cu")
		(net "FM_PCHHOT_N")
	)
	(segment
		(start 325.651622 -46.449234)
		(end 326.999854 -46.449234)
		(width 0.0889)
		(layer "F.Cu")
		(net "FM_PCHHOT_N")
	)
	(segment
		(start 311.18175 -44.526708)
		(end 313.939682 -44.526708)
		(width 0.12954)
		(layer "F.Cu")
		(net "FM_PCHHOT_N")
	)
	(via
		(at 314.42914 -44.03725)
		(size 0.762)
		(drill 0.381)
		(layers "F.Cu" "B.Cu")
		(net "FM_PCHHOT_N")
	)
	(segment
		(start 298.021756 -44.818808)
		(end 298.036996 -44.803568)
		(width 0.12954)
		(layer "F.Cu")
		(net "FM_PASSWORD_CLEAR_N")
	)
	(segment
		(start 330.252578 -49.859946)
		(end 330.10729 -49.859946)
		(width 0.12954)
		(layer "F.Cu")
		(net "FM_PASSWORD_CLEAR_N")
	)
	(segment
		(start 330.10729 -49.859946)
		(end 329.980036 -49.732692)
		(width 0.12954)
		(layer "F.Cu")
		(net "FM_PASSWORD_CLEAR_N")
	)
	(segment
		(start 329.980036 -49.732692)
		(end 329.980036 -49.390046)
		(width 0.12954)
		(layer "F.Cu")
		(net "FM_PASSWORD_CLEAR_N")
	)
	(segment
		(start 298.036996 -44.803568)
		(end 298.036996 -43.994324)
		(width 0.12954)
		(layer "F.Cu")
		(net "FM_PASSWORD_CLEAR_N")
	)
	(via
		(at 298.021756 -44.818808)
		(size 0.508)
		(drill 0.254)
		(layers "F.Cu" "B.Cu")
		(net "FM_PASSWORD_CLEAR_N")
	)
	(via
		(at 330.252578 -49.859946)
		(size 0.4572)
		(drill 0.2032)
		(layers "F.Cu" "B.Cu")
		(net "FM_PASSWORD_CLEAR_N")
	)
	(segment
		(start 326.80148 -47.412148)
		(end 313.51728 -47.412148)
		(width 0.127)
		(layer "In6.Cu")
		(net "FM_PASSWORD_CLEAR_N")
	)
	(segment
		(start 330.252578 -49.859946)
		(end 330.12888 -49.736248)
		(width 0.127)
		(layer "In6.Cu")
		(net "FM_PASSWORD_CLEAR_N")
	)
	(segment
		(start 309.7276 -46.467268)
		(end 308.75732 -45.496988)
		(width 0.127)
		(layer "In6.Cu")
		(net "FM_PASSWORD_CLEAR_N")
	)
	(segment
		(start 313.51728 -47.412148)
		(end 312.5724 -46.467268)
		(width 0.127)
		(layer "In6.Cu")
		(net "FM_PASSWORD_CLEAR_N")
	)
	(segment
		(start 329.59548 -48.910748)
		(end 328.30008 -48.910748)
		(width 0.127)
		(layer "In6.Cu")
		(net "FM_PASSWORD_CLEAR_N")
	)
	(segment
		(start 330.12888 -49.736248)
		(end 330.12888 -49.444148)
		(width 0.127)
		(layer "In6.Cu")
		(net "FM_PASSWORD_CLEAR_N")
	)
	(segment
		(start 330.12888 -49.444148)
		(end 329.59548 -48.910748)
		(width 0.127)
		(layer "In6.Cu")
		(net "FM_PASSWORD_CLEAR_N")
	)
	(segment
		(start 312.5724 -46.467268)
		(end 309.7276 -46.467268)
		(width 0.127)
		(layer "In6.Cu")
		(net "FM_PASSWORD_CLEAR_N")
	)
	(segment
		(start 298.699936 -45.496988)
		(end 298.021756 -44.818808)
		(width 0.127)
		(layer "In6.Cu")
		(net "FM_PASSWORD_CLEAR_N")
	)
	(segment
		(start 308.75732 -45.496988)
		(end 298.699936 -45.496988)
		(width 0.127)
		(layer "In6.Cu")
		(net "FM_PASSWORD_CLEAR_N")
	)
	(segment
		(start 328.30008 -48.910748)
		(end 326.80148 -47.412148)
		(width 0.127)
		(layer "In6.Cu")
		(net "FM_PASSWORD_CLEAR_N")
	)
	(segment
		(start 422.63568 -30.673548)
		(end 415.81324 -37.495988)
		(width 0.127)
		(layer "In15.Cu")
		(net "FM_PASSWORD_CLEAR_N")
	)
	(segment
		(start 330.252578 -49.56429)
		(end 330.252578 -49.859946)
		(width 0.127)
		(layer "In15.Cu")
		(net "FM_PASSWORD_CLEAR_N")
	)
	(segment
		(start 324.79488 -42.436542)
		(end 324.79488 -45.786548)
		(width 0.127)
		(layer "In15.Cu")
		(net "FM_PASSWORD_CLEAR_N")
	)
	(segment
		(start 427.21784 -30.673548)
		(end 422.63568 -30.673548)
		(width 0.127)
		(layer "In15.Cu")
		(net "FM_PASSWORD_CLEAR_N")
	)
	(segment
		(start 428.511462 -29.379926)
		(end 427.21784 -30.673548)
		(width 0.127)
		(layer "In15.Cu")
		(net "FM_PASSWORD_CLEAR_N")
	)
	(segment
		(start 330.8604 -37.793168)
		(end 329.48372 -39.169848)
		(width 0.127)
		(layer "In15.Cu")
		(net "FM_PASSWORD_CLEAR_N")
	)
	(segment
		(start 375.698004 -45.786548)
		(end 372.357904 -49.126648)
		(width 0.127)
		(layer "In15.Cu")
		(net "FM_PASSWORD_CLEAR_N")
	)
	(segment
		(start 324.79488 -45.786548)
		(end 326.9869 -47.978568)
		(width 0.127)
		(layer "In15.Cu")
		(net "FM_PASSWORD_CLEAR_N")
	)
	(segment
		(start 326.9869 -47.978568)
		(end 329.60564 -47.978568)
		(width 0.127)
		(layer "In15.Cu")
		(net "FM_PASSWORD_CLEAR_N")
	)
	(segment
		(start 429.170084 -29.379926)
		(end 428.511462 -29.379926)
		(width 0.127)
		(layer "In15.Cu")
		(net "FM_PASSWORD_CLEAR_N")
	)
	(segment
		(start 393.300204 -45.786548)
		(end 375.698004 -45.786548)
		(width 0.127)
		(layer "In15.Cu")
		(net "FM_PASSWORD_CLEAR_N")
	)
	(segment
		(start 330.08316 -48.456088)
		(end 330.42352 -48.456088)
		(width 0.127)
		(layer "In15.Cu")
		(net "FM_PASSWORD_CLEAR_N")
	)
	(segment
		(start 330.74102 -49.075848)
		(end 330.252578 -49.56429)
		(width 0.127)
		(layer "In15.Cu")
		(net "FM_PASSWORD_CLEAR_N")
	)
	(segment
		(start 401.590764 -37.495988)
		(end 393.300204 -45.786548)
		(width 0.127)
		(layer "In15.Cu")
		(net "FM_PASSWORD_CLEAR_N")
	)
	(segment
		(start 329.60564 -47.978568)
		(end 330.08316 -48.456088)
		(width 0.127)
		(layer "In15.Cu")
		(net "FM_PASSWORD_CLEAR_N")
	)
	(segment
		(start 347.85808 -40.297608)
		(end 345.35364 -37.793168)
		(width 0.127)
		(layer "In15.Cu")
		(net "FM_PASSWORD_CLEAR_N")
	)
	(segment
		(start 345.35364 -37.793168)
		(end 330.8604 -37.793168)
		(width 0.127)
		(layer "In15.Cu")
		(net "FM_PASSWORD_CLEAR_N")
	)
	(segment
		(start 372.357904 -49.126648)
		(end 355.527864 -49.126648)
		(width 0.127)
		(layer "In15.Cu")
		(net "FM_PASSWORD_CLEAR_N")
	)
	(segment
		(start 415.81324 -37.495988)
		(end 401.590764 -37.495988)
		(width 0.127)
		(layer "In15.Cu")
		(net "FM_PASSWORD_CLEAR_N")
	)
	(segment
		(start 329.48372 -39.169848)
		(end 328.061574 -39.169848)
		(width 0.127)
		(layer "In15.Cu")
		(net "FM_PASSWORD_CLEAR_N")
	)
	(segment
		(start 330.74102 -48.773588)
		(end 330.74102 -49.075848)
		(width 0.127)
		(layer "In15.Cu")
		(net "FM_PASSWORD_CLEAR_N")
	)
	(segment
		(start 355.527864 -49.126648)
		(end 347.85808 -41.456864)
		(width 0.127)
		(layer "In15.Cu")
		(net "FM_PASSWORD_CLEAR_N")
	)
	(segment
		(start 330.42352 -48.456088)
		(end 330.74102 -48.773588)
		(width 0.127)
		(layer "In15.Cu")
		(net "FM_PASSWORD_CLEAR_N")
	)
	(segment
		(start 328.061574 -39.169848)
		(end 324.79488 -42.436542)
		(width 0.127)
		(layer "In15.Cu")
		(net "FM_PASSWORD_CLEAR_N")
	)
	(segment
		(start 347.85808 -41.456864)
		(end 347.85808 -40.297608)
		(width 0.127)
		(layer "In15.Cu")
		(net "FM_PASSWORD_CLEAR_N")
	)
	(segment
		(start 168.11371 -129.153666)
		(end 168.11371 -128.354836)
		(width 0.12954)
		(layer "F.Cu")
		(net "FM_P5V_EN")
	)
	(segment
		(start 174.955708 -120.975374)
		(end 174.555658 -121.375424)
		(width 0.12954)
		(layer "F.Cu")
		(net "FM_P5V_EN")
	)
	(via
		(at 168.11371 -128.354836)
		(size 0.508)
		(drill 0.254)
		(layers "F.Cu" "B.Cu")
		(net "FM_P5V_EN")
	)
	(via
		(at 174.555658 -121.375424)
		(size 0.4572)
		(drill 0.254)
		(layers "F.Cu" "B.Cu")
		(net "FM_P5V_EN")
	)
	(segment
		(start 168.11371 -127.817118)
		(end 168.11371 -128.354836)
		(width 0.127)
		(layer "In15.Cu")
		(net "FM_P5V_EN")
	)
	(segment
		(start 174.555404 -121.375424)
		(end 168.11371 -127.817118)
		(width 0.127)
		(layer "In15.Cu")
		(net "FM_P5V_EN")
	)
	(segment
		(start 174.555658 -121.375424)
		(end 174.555404 -121.375424)
		(width 0.127)
		(layer "In15.Cu")
		(net "FM_P5V_EN")
	)
	(segment
		(start 260.504686 -72.841104)
		(end 260.504686 -73.274936)
		(width 0.12954)
		(layer "F.Cu")
		(net "FM_P1V05_PCH_AUX_R_EN")
	)
	(segment
		(start 259.363972 -75.224386)
		(end 259.064506 -75.523852)
		(width 0.12954)
		(layer "F.Cu")
		(net "FM_P1V05_PCH_AUX_R_EN")
	)
	(segment
		(start 259.363972 -74.74966)
		(end 259.363972 -75.224386)
		(width 0.12954)
		(layer "F.Cu")
		(net "FM_P1V05_PCH_AUX_R_EN")
	)
	(segment
		(start 259.363972 -74.41565)
		(end 259.363972 -74.74966)
		(width 0.12954)
		(layer "F.Cu")
		(net "FM_P1V05_PCH_AUX_R_EN")
	)
	(segment
		(start 260.504686 -73.274936)
		(end 259.363972 -74.41565)
		(width 0.12954)
		(layer "F.Cu")
		(net "FM_P1V05_PCH_AUX_R_EN")
	)
	(via
		(at 259.363972 -74.74966)
		(size 0.508)
		(drill 0.254)
		(layers "F.Cu" "B.Cu")
		(net "FM_P1V05_PCH_AUX_R_EN")
	)
	(segment
		(start 259.097526 -75.016106)
		(end 259.097526 -76.158852)
		(width 0.12954)
		(layer "B.Cu")
		(net "FM_P1V05_PCH_AUX_R_EN")
	)
	(segment
		(start 258.50088 -76.780898)
		(end 259.097526 -76.184252)
		(width 0.12954)
		(layer "B.Cu")
		(net "FM_P1V05_PCH_AUX_R_EN")
	)
	(segment
		(start 259.363972 -74.74966)
		(end 259.097526 -75.016106)
		(width 0.12954)
		(layer "B.Cu")
		(net "FM_P1V05_PCH_AUX_R_EN")
	)
	(segment
		(start 259.097526 -76.184252)
		(end 259.097526 -76.158852)
		(width 0.12954)
		(layer "B.Cu")
		(net "FM_P1V05_PCH_AUX_R_EN")
	)
	(segment
		(start 258.50088 -78.177898)
		(end 258.50088 -76.780898)
		(width 0.12954)
		(layer "B.Cu")
		(net "FM_P1V05_PCH_AUX_R_EN")
	)
	(segment
		(start 260.121146 -76.158852)
		(end 259.097526 -76.158852)
		(width 0.12954)
		(layer "B.Cu")
		(net "FM_P1V05_PCH_AUX_R_EN")
	)
	(segment
		(start 259.064506 -76.982828)
		(end 259.064506 -76.323952)
		(width 0.12954)
		(layer "F.Cu")
		(net "FM_P1V05_PCH_AUX_EN")
	)
	(segment
		(start 244.572028 -79.886048)
		(end 245.242588 -79.215488)
		(width 0.12954)
		(layer "F.Cu")
		(net "FM_P1V05_PCH_AUX_EN")
	)
	(segment
		(start 174.955708 -120.175528)
		(end 174.555658 -120.575578)
		(width 0.12954)
		(layer "F.Cu")
		(net "FM_P1V05_PCH_AUX_EN")
	)
	(segment
		(start 252.410468 -79.215488)
		(end 253.82474 -80.62976)
		(width 0.12954)
		(layer "F.Cu")
		(net "FM_P1V05_PCH_AUX_EN")
	)
	(segment
		(start 258.76504 -77.282294)
		(end 259.064506 -76.982828)
		(width 0.12954)
		(layer "F.Cu")
		(net "FM_P1V05_PCH_AUX_EN")
	)
	(segment
		(start 258.76504 -79.479648)
		(end 258.76504 -77.282294)
		(width 0.12954)
		(layer "F.Cu")
		(net "FM_P1V05_PCH_AUX_EN")
	)
	(segment
		(start 253.82474 -80.62976)
		(end 257.614928 -80.62976)
		(width 0.12954)
		(layer "F.Cu")
		(net "FM_P1V05_PCH_AUX_EN")
	)
	(segment
		(start 245.242588 -79.215488)
		(end 252.410468 -79.215488)
		(width 0.12954)
		(layer "F.Cu")
		(net "FM_P1V05_PCH_AUX_EN")
	)
	(segment
		(start 257.614928 -80.62976)
		(end 258.76504 -79.479648)
		(width 0.12954)
		(layer "F.Cu")
		(net "FM_P1V05_PCH_AUX_EN")
	)
	(via
		(at 244.572028 -79.886048)
		(size 0.508)
		(drill 0.254)
		(layers "F.Cu" "B.Cu")
		(net "FM_P1V05_PCH_AUX_EN")
	)
	(via
		(at 244.6782 -88.382348)
		(size 0.508)
		(drill 0.254)
		(layers "F.Cu" "B.Cu")
		(net "FM_P1V05_PCH_AUX_EN")
	)
	(via
		(at 174.555658 -120.575578)
		(size 0.4572)
		(drill 0.254)
		(layers "F.Cu" "B.Cu")
		(net "FM_P1V05_PCH_AUX_EN")
	)
	(segment
		(start 244.851936 -88.382348)
		(end 245.037356 -88.196928)
		(width 0.127)
		(layer "In2.Cu")
		(net "FM_P1V05_PCH_AUX_EN")
	)
	(segment
		(start 243.459 -82.758788)
		(end 243.459 -80.423512)
		(width 0.127)
		(layer "In2.Cu")
		(net "FM_P1V05_PCH_AUX_EN")
	)
	(segment
		(start 245.037356 -84.337144)
		(end 243.459 -82.758788)
		(width 0.127)
		(layer "In2.Cu")
		(net "FM_P1V05_PCH_AUX_EN")
	)
	(segment
		(start 243.459 -80.423512)
		(end 243.996464 -79.886048)
		(width 0.127)
		(layer "In2.Cu")
		(net "FM_P1V05_PCH_AUX_EN")
	)
	(segment
		(start 243.996464 -79.886048)
		(end 244.572028 -79.886048)
		(width 0.127)
		(layer "In2.Cu")
		(net "FM_P1V05_PCH_AUX_EN")
	)
	(segment
		(start 245.037356 -88.196928)
		(end 245.037356 -84.337144)
		(width 0.127)
		(layer "In2.Cu")
		(net "FM_P1V05_PCH_AUX_EN")
	)
	(segment
		(start 244.6782 -88.382348)
		(end 244.851936 -88.382348)
		(width 0.127)
		(layer "In2.Cu")
		(net "FM_P1V05_PCH_AUX_EN")
	)
	(segment
		(start 182.378604 -94.4118)
		(end 182.378604 -95.739204)
		(width 0.127)
		(layer "In13.Cu")
		(net "FM_P1V05_PCH_AUX_EN")
	)
	(segment
		(start 176.562766 -105.265474)
		(end 176.562766 -107.938316)
		(width 0.127)
		(layer "In13.Cu")
		(net "FM_P1V05_PCH_AUX_EN")
	)
	(segment
		(start 176.319434 -108.181648)
		(end 175.96104 -108.181648)
		(width 0.127)
		(layer "In13.Cu")
		(net "FM_P1V05_PCH_AUX_EN")
	)
	(segment
		(start 175.9331 -101.387148)
		(end 175.9331 -102.034848)
		(width 0.127)
		(layer "In13.Cu")
		(net "FM_P1V05_PCH_AUX_EN")
	)
	(segment
		(start 243.990622 -88.416638)
		(end 240.293906 -92.113354)
		(width 0.127)
		(layer "In13.Cu")
		(net "FM_P1V05_PCH_AUX_EN")
	)
	(segment
		(start 175.39462 -102.573328)
		(end 175.39462 -104.097328)
		(width 0.127)
		(layer "In13.Cu")
		(net "FM_P1V05_PCH_AUX_EN")
	)
	(segment
		(start 187.579 -93.0148)
		(end 186.309 -94.2848)
		(width 0.127)
		(layer "In13.Cu")
		(net "FM_P1V05_PCH_AUX_EN")
	)
	(segment
		(start 187.579 -92.426282)
		(end 187.579 -93.0148)
		(width 0.127)
		(layer "In13.Cu")
		(net "FM_P1V05_PCH_AUX_EN")
	)
	(segment
		(start 216.045034 -87.399368)
		(end 192.605914 -87.399368)
		(width 0.127)
		(layer "In13.Cu")
		(net "FM_P1V05_PCH_AUX_EN")
	)
	(segment
		(start 192.605914 -87.399368)
		(end 187.579 -92.426282)
		(width 0.127)
		(layer "In13.Cu")
		(net "FM_P1V05_PCH_AUX_EN")
	)
	(segment
		(start 175.52924 -120.170448)
		(end 174.960788 -120.170448)
		(width 0.127)
		(layer "In13.Cu")
		(net "FM_P1V05_PCH_AUX_EN")
	)
	(segment
		(start 240.293906 -92.113354)
		(end 220.75902 -92.113354)
		(width 0.127)
		(layer "In13.Cu")
		(net "FM_P1V05_PCH_AUX_EN")
	)
	(segment
		(start 174.960788 -120.170448)
		(end 174.555658 -120.575578)
		(width 0.127)
		(layer "In13.Cu")
		(net "FM_P1V05_PCH_AUX_EN")
	)
	(segment
		(start 178.2064 -99.113848)
		(end 175.9331 -101.387148)
		(width 0.127)
		(layer "In13.Cu")
		(net "FM_P1V05_PCH_AUX_EN")
	)
	(segment
		(start 178.2064 -98.590608)
		(end 178.2064 -99.113848)
		(width 0.127)
		(layer "In13.Cu")
		(net "FM_P1V05_PCH_AUX_EN")
	)
	(segment
		(start 175.7553 -119.944388)
		(end 175.52924 -120.170448)
		(width 0.127)
		(layer "In13.Cu")
		(net "FM_P1V05_PCH_AUX_EN")
	)
	(segment
		(start 181.32298 -96.794828)
		(end 180.00218 -96.794828)
		(width 0.127)
		(layer "In13.Cu")
		(net "FM_P1V05_PCH_AUX_EN")
	)
	(segment
		(start 186.309 -94.2848)
		(end 182.505604 -94.2848)
		(width 0.127)
		(layer "In13.Cu")
		(net "FM_P1V05_PCH_AUX_EN")
	)
	(segment
		(start 182.378604 -95.739204)
		(end 181.32298 -96.794828)
		(width 0.127)
		(layer "In13.Cu")
		(net "FM_P1V05_PCH_AUX_EN")
	)
	(segment
		(start 244.64391 -88.416638)
		(end 243.990622 -88.416638)
		(width 0.127)
		(layer "In13.Cu")
		(net "FM_P1V05_PCH_AUX_EN")
	)
	(segment
		(start 175.9331 -102.034848)
		(end 175.39462 -102.573328)
		(width 0.127)
		(layer "In13.Cu")
		(net "FM_P1V05_PCH_AUX_EN")
	)
	(segment
		(start 175.96104 -108.181648)
		(end 175.7553 -108.387388)
		(width 0.127)
		(layer "In13.Cu")
		(net "FM_P1V05_PCH_AUX_EN")
	)
	(segment
		(start 175.7553 -108.387388)
		(end 175.7553 -119.944388)
		(width 0.127)
		(layer "In13.Cu")
		(net "FM_P1V05_PCH_AUX_EN")
	)
	(segment
		(start 175.39462 -104.097328)
		(end 176.562766 -105.265474)
		(width 0.127)
		(layer "In13.Cu")
		(net "FM_P1V05_PCH_AUX_EN")
	)
	(segment
		(start 182.505604 -94.2848)
		(end 182.378604 -94.4118)
		(width 0.127)
		(layer "In13.Cu")
		(net "FM_P1V05_PCH_AUX_EN")
	)
	(segment
		(start 180.00218 -96.794828)
		(end 178.2064 -98.590608)
		(width 0.127)
		(layer "In13.Cu")
		(net "FM_P1V05_PCH_AUX_EN")
	)
	(segment
		(start 220.75902 -92.113354)
		(end 216.045034 -87.399368)
		(width 0.127)
		(layer "In13.Cu")
		(net "FM_P1V05_PCH_AUX_EN")
	)
	(segment
		(start 176.562766 -107.938316)
		(end 176.319434 -108.181648)
		(width 0.127)
		(layer "In13.Cu")
		(net "FM_P1V05_PCH_AUX_EN")
	)
	(segment
		(start 244.6782 -88.382348)
		(end 244.64391 -88.416638)
		(width 0.127)
		(layer "In13.Cu")
		(net "FM_P1V05_PCH_AUX_EN")
	)
	(segment
		(start 166.52748 -109.388148)
		(end 166.34968 -109.565948)
		(width 0.12954)
		(layer "F.Cu")
		(net "FM_OCP_SFF_PWR_GOOD_R")
	)
	(segment
		(start 166.34968 -109.565948)
		(end 165.04793 -109.565948)
		(width 0.12954)
		(layer "F.Cu")
		(net "FM_OCP_SFF_PWR_GOOD_R")
	)
	(segment
		(start 169.768266 -109.388148)
		(end 166.52748 -109.388148)
		(width 0.12954)
		(layer "F.Cu")
		(net "FM_OCP_SFF_PWR_GOOD_R")
	)
	(segment
		(start 170.155616 -109.775498)
		(end 169.768266 -109.388148)
		(width 0.12954)
		(layer "F.Cu")
		(net "FM_OCP_SFF_PWR_GOOD_R")
	)
	(via
		(at 166.52748 -109.388148)
		(size 0.762)
		(drill 0.381)
		(layers "F.Cu" "B.Cu")
		(net "FM_OCP_SFF_PWR_GOOD_R")
	)
	(segment
		(start 457.28636 -98.313748)
		(end 457.46416 -98.491548)
		(width 0.12954)
		(layer "F.Cu")
		(net "FM_OCP_SFF_PWR_GOOD")
	)
	(segment
		(start 164.44468 -110.277148)
		(end 164.24783 -110.080298)
		(width 0.12954)
		(layer "F.Cu")
		(net "FM_OCP_SFF_PWR_GOOD")
	)
	(segment
		(start 164.24783 -110.080298)
		(end 164.24783 -109.565948)
		(width 0.12954)
		(layer "F.Cu")
		(net "FM_OCP_SFF_PWR_GOOD")
	)
	(segment
		(start 161.238692 -110.9091)
		(end 163.812728 -110.9091)
		(width 0.12954)
		(layer "F.Cu")
		(net "FM_OCP_SFF_PWR_GOOD")
	)
	(segment
		(start 457.46416 -98.491548)
		(end 458.606906 -98.491548)
		(width 0.12954)
		(layer "F.Cu")
		(net "FM_OCP_SFF_PWR_GOOD")
	)
	(segment
		(start 452.56196 -11.26998)
		(end 452.56196 -13.378688)
		(width 0.12954)
		(layer "F.Cu")
		(net "FM_OCP_SFF_PWR_GOOD")
	)
	(segment
		(start 452.56196 -13.378688)
		(end 452.570596 -13.387324)
		(width 0.12954)
		(layer "F.Cu")
		(net "FM_OCP_SFF_PWR_GOOD")
	)
	(segment
		(start 452.570596 -13.387324)
		(end 452.570596 -13.833348)
		(width 0.12954)
		(layer "F.Cu")
		(net "FM_OCP_SFF_PWR_GOOD")
	)
	(segment
		(start 163.812728 -110.9091)
		(end 164.44468 -110.277148)
		(width 0.12954)
		(layer "F.Cu")
		(net "FM_OCP_SFF_PWR_GOOD")
	)
	(segment
		(start 458.606906 -98.491548)
		(end 458.629766 -98.514408)
		(width 0.12954)
		(layer "F.Cu")
		(net "FM_OCP_SFF_PWR_GOOD")
	)
	(via
		(at 457.28636 -98.313748)
		(size 0.508)
		(drill 0.254)
		(layers "F.Cu" "B.Cu")
		(net "FM_OCP_SFF_PWR_GOOD")
	)
	(via
		(at 452.570596 -13.833348)
		(size 0.508)
		(drill 0.254)
		(layers "F.Cu" "B.Cu")
		(net "FM_OCP_SFF_PWR_GOOD")
	)
	(via
		(at 164.44468 -110.277148)
		(size 0.508)
		(drill 0.254)
		(layers "F.Cu" "B.Cu")
		(net "FM_OCP_SFF_PWR_GOOD")
	)
	(via
		(at 273.850354 -105.133394)
		(size 0.508)
		(drill 0.254)
		(layers "F.Cu" "B.Cu")
		(net "FM_OCP_SFF_PWR_GOOD")
	)
	(via
		(at 202.78598 -111.742728)
		(size 0.508)
		(drill 0.254)
		(layers "F.Cu" "B.Cu")
		(net "FM_OCP_SFF_PWR_GOOD")
	)
	(segment
		(start 174.153322 -109.09554)
		(end 174.153322 -109.560106)
		(width 0.12954)
		(layer "B.Cu")
		(net "FM_OCP_SFF_PWR_GOOD")
	)
	(segment
		(start 199.87514 -108.039408)
		(end 199.49922 -107.663488)
		(width 0.12954)
		(layer "B.Cu")
		(net "FM_OCP_SFF_PWR_GOOD")
	)
	(segment
		(start 183.651652 -108.970826)
		(end 174.278036 -108.970826)
		(width 0.12954)
		(layer "B.Cu")
		(net "FM_OCP_SFF_PWR_GOOD")
	)
	(segment
		(start 200.16089 -106.056938)
		(end 199.49922 -105.395268)
		(width 0.12954)
		(layer "B.Cu")
		(net "FM_OCP_SFF_PWR_GOOD")
	)
	(segment
		(start 191.16548 -103.063548)
		(end 190.72098 -103.508048)
		(width 0.12954)
		(layer "B.Cu")
		(net "FM_OCP_SFF_PWR_GOOD")
	)
	(segment
		(start 190.72098 -104.3559)
		(end 187.700412 -107.376468)
		(width 0.12954)
		(layer "B.Cu")
		(net "FM_OCP_SFF_PWR_GOOD")
	)
	(segment
		(start 167.25646 -110.277148)
		(end 164.44468 -110.277148)
		(width 0.12954)
		(layer "B.Cu")
		(net "FM_OCP_SFF_PWR_GOOD")
	)
	(segment
		(start 187.700412 -107.376468)
		(end 183.86298 -107.376468)
		(width 0.12954)
		(layer "B.Cu")
		(net "FM_OCP_SFF_PWR_GOOD")
	)
	(segment
		(start 202.78598 -111.742728)
		(end 203.327 -111.201708)
		(width 0.12954)
		(layer "B.Cu")
		(net "FM_OCP_SFF_PWR_GOOD")
	)
	(segment
		(start 171.41698 -110.236508)
		(end 169.89298 -110.236508)
		(width 0.12954)
		(layer "B.Cu")
		(net "FM_OCP_SFF_PWR_GOOD")
	)
	(segment
		(start 203.327 -111.201708)
		(end 203.327 -109.99597)
		(width 0.12954)
		(layer "B.Cu")
		(net "FM_OCP_SFF_PWR_GOOD")
	)
	(segment
		(start 174.153322 -109.560106)
		(end 173.9392 -109.774228)
		(width 0.12954)
		(layer "B.Cu")
		(net "FM_OCP_SFF_PWR_GOOD")
	)
	(segment
		(start 199.49922 -107.119928)
		(end 200.16089 -106.458258)
		(width 0.12954)
		(layer "B.Cu")
		(net "FM_OCP_SFF_PWR_GOOD")
	)
	(segment
		(start 203.397612 -109.197902)
		(end 203.397612 -108.56976)
		(width 0.12954)
		(layer "B.Cu")
		(net "FM_OCP_SFF_PWR_GOOD")
	)
	(segment
		(start 203.533502 -109.333792)
		(end 203.397612 -109.197902)
		(width 0.12954)
		(layer "B.Cu")
		(net "FM_OCP_SFF_PWR_GOOD")
	)
	(segment
		(start 190.72098 -103.508048)
		(end 190.72098 -104.3559)
		(width 0.12954)
		(layer "B.Cu")
		(net "FM_OCP_SFF_PWR_GOOD")
	)
	(segment
		(start 183.86298 -107.376468)
		(end 183.75122 -107.488228)
		(width 0.12954)
		(layer "B.Cu")
		(net "FM_OCP_SFF_PWR_GOOD")
	)
	(segment
		(start 169.89298 -110.236508)
		(end 169.33926 -109.682788)
		(width 0.12954)
		(layer "B.Cu")
		(net "FM_OCP_SFF_PWR_GOOD")
	)
	(segment
		(start 200.16089 -106.458258)
		(end 200.16089 -106.056938)
		(width 0.12954)
		(layer "B.Cu")
		(net "FM_OCP_SFF_PWR_GOOD")
	)
	(segment
		(start 173.9392 -109.774228)
		(end 171.87926 -109.774228)
		(width 0.12954)
		(layer "B.Cu")
		(net "FM_OCP_SFF_PWR_GOOD")
	)
	(segment
		(start 202.86726 -108.039408)
		(end 199.87514 -108.039408)
		(width 0.12954)
		(layer "B.Cu")
		(net "FM_OCP_SFF_PWR_GOOD")
	)
	(segment
		(start 171.87926 -109.774228)
		(end 171.41698 -110.236508)
		(width 0.12954)
		(layer "B.Cu")
		(net "FM_OCP_SFF_PWR_GOOD")
	)
	(segment
		(start 199.49922 -105.189528)
		(end 197.37324 -103.063548)
		(width 0.12954)
		(layer "B.Cu")
		(net "FM_OCP_SFF_PWR_GOOD")
	)
	(segment
		(start 199.49922 -105.395268)
		(end 199.49922 -105.189528)
		(width 0.12954)
		(layer "B.Cu")
		(net "FM_OCP_SFF_PWR_GOOD")
	)
	(segment
		(start 199.49922 -107.663488)
		(end 199.49922 -107.119928)
		(width 0.12954)
		(layer "B.Cu")
		(net "FM_OCP_SFF_PWR_GOOD")
	)
	(segment
		(start 183.75122 -108.871258)
		(end 183.651652 -108.970826)
		(width 0.12954)
		(layer "B.Cu")
		(net "FM_OCP_SFF_PWR_GOOD")
	)
	(segment
		(start 197.37324 -103.063548)
		(end 191.16548 -103.063548)
		(width 0.12954)
		(layer "B.Cu")
		(net "FM_OCP_SFF_PWR_GOOD")
	)
	(segment
		(start 203.533502 -109.789468)
		(end 203.533502 -109.333792)
		(width 0.12954)
		(layer "B.Cu")
		(net "FM_OCP_SFF_PWR_GOOD")
	)
	(segment
		(start 203.327 -109.99597)
		(end 203.533502 -109.789468)
		(width 0.12954)
		(layer "B.Cu")
		(net "FM_OCP_SFF_PWR_GOOD")
	)
	(segment
		(start 183.75122 -107.488228)
		(end 183.75122 -108.871258)
		(width 0.12954)
		(layer "B.Cu")
		(net "FM_OCP_SFF_PWR_GOOD")
	)
	(segment
		(start 169.33926 -109.682788)
		(end 167.85082 -109.682788)
		(width 0.12954)
		(layer "B.Cu")
		(net "FM_OCP_SFF_PWR_GOOD")
	)
	(segment
		(start 167.85082 -109.682788)
		(end 167.25646 -110.277148)
		(width 0.12954)
		(layer "B.Cu")
		(net "FM_OCP_SFF_PWR_GOOD")
	)
	(segment
		(start 174.278036 -108.970826)
		(end 174.153322 -109.09554)
		(width 0.12954)
		(layer "B.Cu")
		(net "FM_OCP_SFF_PWR_GOOD")
	)
	(segment
		(start 203.397612 -108.56976)
		(end 202.86726 -108.039408)
		(width 0.12954)
		(layer "B.Cu")
		(net "FM_OCP_SFF_PWR_GOOD")
	)
	(segment
		(start 454.1266 -13.904468)
		(end 457.48956 -17.267428)
		(width 0.127)
		(layer "In2.Cu")
		(net "FM_OCP_SFF_PWR_GOOD")
	)
	(segment
		(start 439.299604 -82.083148)
		(end 450.6087 -82.083148)
		(width 0.127)
		(layer "In2.Cu")
		(net "FM_OCP_SFF_PWR_GOOD")
	)
	(segment
		(start 452.570596 -13.833348)
		(end 452.641716 -13.904468)
		(width 0.127)
		(layer "In2.Cu")
		(net "FM_OCP_SFF_PWR_GOOD")
	)
	(segment
		(start 450.6087 -82.083148)
		(end 459.04658 -90.521028)
		(width 0.127)
		(layer "In2.Cu")
		(net "FM_OCP_SFF_PWR_GOOD")
	)
	(segment
		(start 457.0095 -41.499028)
		(end 451.7136 -46.794928)
		(width 0.127)
		(layer "In2.Cu")
		(net "FM_OCP_SFF_PWR_GOOD")
	)
	(segment
		(start 459.04658 -97.518728)
		(end 458.07376 -98.491548)
		(width 0.127)
		(layer "In2.Cu")
		(net "FM_OCP_SFF_PWR_GOOD")
	)
	(segment
		(start 459.04658 -90.521028)
		(end 459.04658 -97.518728)
		(width 0.127)
		(layer "In2.Cu")
		(net "FM_OCP_SFF_PWR_GOOD")
	)
	(segment
		(start 457.0095 -38.697408)
		(end 457.0095 -41.499028)
		(width 0.127)
		(layer "In2.Cu")
		(net "FM_OCP_SFF_PWR_GOOD")
	)
	(segment
		(start 441.833 -46.794928)
		(end 440.61888 -48.009048)
		(width 0.127)
		(layer "In2.Cu")
		(net "FM_OCP_SFF_PWR_GOOD")
	)
	(segment
		(start 452.641716 -13.904468)
		(end 454.1266 -13.904468)
		(width 0.127)
		(layer "In2.Cu")
		(net "FM_OCP_SFF_PWR_GOOD")
	)
	(segment
		(start 458.07376 -98.491548)
		(end 457.46416 -98.491548)
		(width 0.127)
		(layer "In2.Cu")
		(net "FM_OCP_SFF_PWR_GOOD")
	)
	(segment
		(start 440.61888 -60.289948)
		(end 436.81396 -64.094868)
		(width 0.127)
		(layer "In2.Cu")
		(net "FM_OCP_SFF_PWR_GOOD")
	)
	(segment
		(start 457.48956 -38.217348)
		(end 457.0095 -38.697408)
		(width 0.127)
		(layer "In2.Cu")
		(net "FM_OCP_SFF_PWR_GOOD")
	)
	(segment
		(start 451.7136 -46.794928)
		(end 441.833 -46.794928)
		(width 0.127)
		(layer "In2.Cu")
		(net "FM_OCP_SFF_PWR_GOOD")
	)
	(segment
		(start 457.48956 -17.267428)
		(end 457.48956 -38.217348)
		(width 0.127)
		(layer "In2.Cu")
		(net "FM_OCP_SFF_PWR_GOOD")
	)
	(segment
		(start 440.61888 -48.009048)
		(end 440.61888 -60.289948)
		(width 0.127)
		(layer "In2.Cu")
		(net "FM_OCP_SFF_PWR_GOOD")
	)
	(segment
		(start 436.81396 -64.094868)
		(end 436.81396 -79.597504)
		(width 0.127)
		(layer "In2.Cu")
		(net "FM_OCP_SFF_PWR_GOOD")
	)
	(segment
		(start 457.46416 -98.491548)
		(end 457.28636 -98.313748)
		(width 0.127)
		(layer "In2.Cu")
		(net "FM_OCP_SFF_PWR_GOOD")
	)
	(segment
		(start 436.81396 -79.597504)
		(end 439.299604 -82.083148)
		(width 0.127)
		(layer "In2.Cu")
		(net "FM_OCP_SFF_PWR_GOOD")
	)
	(segment
		(start 381.01778 -106.644948)
		(end 408.253946 -106.644948)
		(width 0.127)
		(layer "In4.Cu")
		(net "FM_OCP_SFF_PWR_GOOD")
	)
	(segment
		(start 274.843748 -106.126788)
		(end 308.37632 -106.126788)
		(width 0.127)
		(layer "In4.Cu")
		(net "FM_OCP_SFF_PWR_GOOD")
	)
	(segment
		(start 308.37632 -106.126788)
		(end 309.06466 -106.815128)
		(width 0.127)
		(layer "In4.Cu")
		(net "FM_OCP_SFF_PWR_GOOD")
	)
	(segment
		(start 273.850354 -105.133394)
		(end 274.843748 -106.126788)
		(width 0.127)
		(layer "In4.Cu")
		(net "FM_OCP_SFF_PWR_GOOD")
	)
	(segment
		(start 408.253946 -106.644948)
		(end 414.664906 -113.055908)
		(width 0.127)
		(layer "In4.Cu")
		(net "FM_OCP_SFF_PWR_GOOD")
	)
	(segment
		(start 366.3823 -107.076748)
		(end 380.58598 -107.076748)
		(width 0.127)
		(layer "In4.Cu")
		(net "FM_OCP_SFF_PWR_GOOD")
	)
	(segment
		(start 414.664906 -113.055908)
		(end 437.421274 -113.055908)
		(width 0.127)
		(layer "In4.Cu")
		(net "FM_OCP_SFF_PWR_GOOD")
	)
	(segment
		(start 310.43118 -106.644948)
		(end 365.9505 -106.644948)
		(width 0.127)
		(layer "In4.Cu")
		(net "FM_OCP_SFF_PWR_GOOD")
	)
	(segment
		(start 380.58598 -107.076748)
		(end 381.01778 -106.644948)
		(width 0.127)
		(layer "In4.Cu")
		(net "FM_OCP_SFF_PWR_GOOD")
	)
	(segment
		(start 448.328034 -102.149148)
		(end 452.15302 -102.149148)
		(width 0.127)
		(layer "In4.Cu")
		(net "FM_OCP_SFF_PWR_GOOD")
	)
	(segment
		(start 309.06466 -106.815128)
		(end 310.261 -106.815128)
		(width 0.127)
		(layer "In4.Cu")
		(net "FM_OCP_SFF_PWR_GOOD")
	)
	(segment
		(start 455.98842 -98.313748)
		(end 457.28636 -98.313748)
		(width 0.127)
		(layer "In4.Cu")
		(net "FM_OCP_SFF_PWR_GOOD")
	)
	(segment
		(start 452.15302 -102.149148)
		(end 455.98842 -98.313748)
		(width 0.127)
		(layer "In4.Cu")
		(net "FM_OCP_SFF_PWR_GOOD")
	)
	(segment
		(start 365.9505 -106.644948)
		(end 366.3823 -107.076748)
		(width 0.127)
		(layer "In4.Cu")
		(net "FM_OCP_SFF_PWR_GOOD")
	)
	(segment
		(start 437.421274 -113.055908)
		(end 448.328034 -102.149148)
		(width 0.127)
		(layer "In4.Cu")
		(net "FM_OCP_SFF_PWR_GOOD")
	)
	(segment
		(start 310.261 -106.815128)
		(end 310.43118 -106.644948)
		(width 0.127)
		(layer "In4.Cu")
		(net "FM_OCP_SFF_PWR_GOOD")
	)
	(segment
		(start 247.113044 -111.968788)
		(end 263.521444 -111.968788)
		(width 0.127)
		(layer "In13.Cu")
		(net "FM_OCP_SFF_PWR_GOOD")
	)
	(segment
		(start 243.258848 -112.108488)
		(end 244.196108 -113.045748)
		(width 0.127)
		(layer "In13.Cu")
		(net "FM_OCP_SFF_PWR_GOOD")
	)
	(segment
		(start 219.20454 -111.285782)
		(end 237.134908 -111.285782)
		(width 0.127)
		(layer "In13.Cu")
		(net "FM_OCP_SFF_PWR_GOOD")
	)
	(segment
		(start 237.957614 -112.108488)
		(end 243.258848 -112.108488)
		(width 0.127)
		(layer "In13.Cu")
		(net "FM_OCP_SFF_PWR_GOOD")
	)
	(segment
		(start 218.549474 -111.940848)
		(end 219.20454 -111.285782)
		(width 0.127)
		(layer "In13.Cu")
		(net "FM_OCP_SFF_PWR_GOOD")
	)
	(segment
		(start 202.78598 -111.742728)
		(end 203.356972 -112.31372)
		(width 0.127)
		(layer "In13.Cu")
		(net "FM_OCP_SFF_PWR_GOOD")
	)
	(segment
		(start 244.196108 -113.045748)
		(end 246.036084 -113.045748)
		(width 0.127)
		(layer "In13.Cu")
		(net "FM_OCP_SFF_PWR_GOOD")
	)
	(segment
		(start 237.134908 -111.285782)
		(end 237.957614 -112.108488)
		(width 0.127)
		(layer "In13.Cu")
		(net "FM_OCP_SFF_PWR_GOOD")
	)
	(segment
		(start 246.036084 -113.045748)
		(end 247.113044 -111.968788)
		(width 0.127)
		(layer "In13.Cu")
		(net "FM_OCP_SFF_PWR_GOOD")
	)
	(segment
		(start 203.356972 -112.31372)
		(end 207.55991 -112.31372)
		(width 0.127)
		(layer "In13.Cu")
		(net "FM_OCP_SFF_PWR_GOOD")
	)
	(segment
		(start 270.356838 -105.133394)
		(end 273.850354 -105.133394)
		(width 0.127)
		(layer "In13.Cu")
		(net "FM_OCP_SFF_PWR_GOOD")
	)
	(segment
		(start 207.932782 -111.940848)
		(end 218.549474 -111.940848)
		(width 0.127)
		(layer "In13.Cu")
		(net "FM_OCP_SFF_PWR_GOOD")
	)
	(segment
		(start 263.521444 -111.968788)
		(end 270.356838 -105.133394)
		(width 0.127)
		(layer "In13.Cu")
		(net "FM_OCP_SFF_PWR_GOOD")
	)
	(segment
		(start 207.55991 -112.31372)
		(end 207.932782 -111.940848)
		(width 0.127)
		(layer "In13.Cu")
		(net "FM_OCP_SFF_PWR_GOOD")
	)
	(segment
		(start 453.98182 -100.38334)
		(end 459.1558 -100.38334)
		(width 0.12954)
		(layer "F.Cu")
		(net "FM_NCSI_OCP_V3_1_R_OE")
	)
	(segment
		(start 459.6257 -97.06102)
		(end 460.280512 -96.406208)
		(width 0.12954)
		(layer "F.Cu")
		(net "FM_NCSI_OCP_V3_1_R_OE")
	)
	(segment
		(start 449.965572 -89.731088)
		(end 453.05726 -92.822776)
		(width 0.12954)
		(layer "F.Cu")
		(net "FM_NCSI_OCP_V3_1_R_OE")
	)
	(segment
		(start 460.280512 -96.406208)
		(end 463.065876 -96.406208)
		(width 0.12954)
		(layer "F.Cu")
		(net "FM_NCSI_OCP_V3_1_R_OE")
	)
	(segment
		(start 459.6257 -99.91344)
		(end 459.6257 -97.06102)
		(width 0.12954)
		(layer "F.Cu")
		(net "FM_NCSI_OCP_V3_1_R_OE")
	)
	(segment
		(start 439.777124 -89.731088)
		(end 449.965572 -89.731088)
		(width 0.12954)
		(layer "F.Cu")
		(net "FM_NCSI_OCP_V3_1_R_OE")
	)
	(segment
		(start 459.1558 -100.38334)
		(end 459.6257 -99.91344)
		(width 0.12954)
		(layer "F.Cu")
		(net "FM_NCSI_OCP_V3_1_R_OE")
	)
	(segment
		(start 185.355738 -115.375436)
		(end 185.755788 -115.775486)
		(width 0.12954)
		(layer "F.Cu")
		(net "FM_NCSI_OCP_V3_1_R_OE")
	)
	(segment
		(start 453.05726 -92.822776)
		(end 453.05726 -99.45878)
		(width 0.12954)
		(layer "F.Cu")
		(net "FM_NCSI_OCP_V3_1_R_OE")
	)
	(segment
		(start 453.05726 -99.45878)
		(end 453.98182 -100.38334)
		(width 0.12954)
		(layer "F.Cu")
		(net "FM_NCSI_OCP_V3_1_R_OE")
	)
	(segment
		(start 438.237376 -91.270836)
		(end 439.777124 -89.731088)
		(width 0.12954)
		(layer "F.Cu")
		(net "FM_NCSI_OCP_V3_1_R_OE")
	)
	(via
		(at 438.237376 -91.270836)
		(size 0.508)
		(drill 0.254)
		(layers "F.Cu" "B.Cu")
		(net "FM_NCSI_OCP_V3_1_R_OE")
	)
	(via
		(at 185.755788 -115.775486)
		(size 0.4572)
		(drill 0.254)
		(layers "F.Cu" "B.Cu")
		(net "FM_NCSI_OCP_V3_1_R_OE")
	)
	(segment
		(start 233.037888 -114.066828)
		(end 222.14332 -114.066828)
		(width 0.127)
		(layer "In15.Cu")
		(net "FM_NCSI_OCP_V3_1_R_OE")
	)
	(segment
		(start 198.46036 -119.619268)
		(end 197.63486 -119.619268)
		(width 0.127)
		(layer "In15.Cu")
		(net "FM_NCSI_OCP_V3_1_R_OE")
	)
	(segment
		(start 270.227806 -118.176548)
		(end 268.538706 -119.865648)
		(width 0.127)
		(layer "In15.Cu")
		(net "FM_NCSI_OCP_V3_1_R_OE")
	)
	(segment
		(start 238.59236 -115.214908)
		(end 234.185968 -115.214908)
		(width 0.127)
		(layer "In15.Cu")
		(net "FM_NCSI_OCP_V3_1_R_OE")
	)
	(segment
		(start 329.54468 -118.201948)
		(end 327.46188 -118.201948)
		(width 0.127)
		(layer "In15.Cu")
		(net "FM_NCSI_OCP_V3_1_R_OE")
	)
	(segment
		(start 220.99524 -115.214908)
		(end 216.34958 -115.214908)
		(width 0.127)
		(layer "In15.Cu")
		(net "FM_NCSI_OCP_V3_1_R_OE")
	)
	(segment
		(start 434.516784 -112.287304)
		(end 430.561496 -112.287304)
		(width 0.127)
		(layer "In15.Cu")
		(net "FM_NCSI_OCP_V3_1_R_OE")
	)
	(segment
		(start 199.448928 -118.6307)
		(end 198.46036 -119.619268)
		(width 0.127)
		(layer "In15.Cu")
		(net "FM_NCSI_OCP_V3_1_R_OE")
	)
	(segment
		(start 239.3569 -115.979448)
		(end 238.59236 -115.214908)
		(width 0.127)
		(layer "In15.Cu")
		(net "FM_NCSI_OCP_V3_1_R_OE")
	)
	(segment
		(start 331.1525 -116.594128)
		(end 329.54468 -118.201948)
		(width 0.127)
		(layer "In15.Cu")
		(net "FM_NCSI_OCP_V3_1_R_OE")
	)
	(segment
		(start 437.765698 -109.03839)
		(end 434.516784 -112.287304)
		(width 0.127)
		(layer "In15.Cu")
		(net "FM_NCSI_OCP_V3_1_R_OE")
	)
	(segment
		(start 196.83222 -118.816628)
		(end 195.9864 -118.816628)
		(width 0.127)
		(layer "In15.Cu")
		(net "FM_NCSI_OCP_V3_1_R_OE")
	)
	(segment
		(start 437.765698 -91.742514)
		(end 437.765698 -109.03839)
		(width 0.127)
		(layer "In15.Cu")
		(net "FM_NCSI_OCP_V3_1_R_OE")
	)
	(segment
		(start 438.237376 -91.270836)
		(end 437.765698 -91.742514)
		(width 0.127)
		(layer "In15.Cu")
		(net "FM_NCSI_OCP_V3_1_R_OE")
	)
	(segment
		(start 194.9577 -119.845328)
		(end 194.00139 -119.845328)
		(width 0.127)
		(layer "In15.Cu")
		(net "FM_NCSI_OCP_V3_1_R_OE")
	)
	(segment
		(start 195.9864 -118.816628)
		(end 194.9577 -119.845328)
		(width 0.127)
		(layer "In15.Cu")
		(net "FM_NCSI_OCP_V3_1_R_OE")
	)
	(segment
		(start 216.34958 -115.214908)
		(end 212.933788 -118.6307)
		(width 0.127)
		(layer "In15.Cu")
		(net "FM_NCSI_OCP_V3_1_R_OE")
	)
	(segment
		(start 326.01408 -116.754148)
		(end 323.22008 -116.754148)
		(width 0.127)
		(layer "In15.Cu")
		(net "FM_NCSI_OCP_V3_1_R_OE")
	)
	(segment
		(start 426.254672 -116.594128)
		(end 331.1525 -116.594128)
		(width 0.127)
		(layer "In15.Cu")
		(net "FM_NCSI_OCP_V3_1_R_OE")
	)
	(segment
		(start 249.18797 -119.865648)
		(end 245.30177 -115.979448)
		(width 0.127)
		(layer "In15.Cu")
		(net "FM_NCSI_OCP_V3_1_R_OE")
	)
	(segment
		(start 197.63486 -119.619268)
		(end 196.83222 -118.816628)
		(width 0.127)
		(layer "In15.Cu")
		(net "FM_NCSI_OCP_V3_1_R_OE")
	)
	(segment
		(start 245.30177 -115.979448)
		(end 239.3569 -115.979448)
		(width 0.127)
		(layer "In15.Cu")
		(net "FM_NCSI_OCP_V3_1_R_OE")
	)
	(segment
		(start 323.22008 -116.754148)
		(end 322.63588 -117.338348)
		(width 0.127)
		(layer "In15.Cu")
		(net "FM_NCSI_OCP_V3_1_R_OE")
	)
	(segment
		(start 430.561496 -112.287304)
		(end 426.254672 -116.594128)
		(width 0.127)
		(layer "In15.Cu")
		(net "FM_NCSI_OCP_V3_1_R_OE")
	)
	(segment
		(start 327.46188 -118.201948)
		(end 326.01408 -116.754148)
		(width 0.127)
		(layer "In15.Cu")
		(net "FM_NCSI_OCP_V3_1_R_OE")
	)
	(segment
		(start 282.8925 -118.176548)
		(end 270.227806 -118.176548)
		(width 0.127)
		(layer "In15.Cu")
		(net "FM_NCSI_OCP_V3_1_R_OE")
	)
	(segment
		(start 322.63588 -117.338348)
		(end 283.7307 -117.338348)
		(width 0.127)
		(layer "In15.Cu")
		(net "FM_NCSI_OCP_V3_1_R_OE")
	)
	(segment
		(start 212.933788 -118.6307)
		(end 199.448928 -118.6307)
		(width 0.127)
		(layer "In15.Cu")
		(net "FM_NCSI_OCP_V3_1_R_OE")
	)
	(segment
		(start 283.7307 -117.338348)
		(end 282.8925 -118.176548)
		(width 0.127)
		(layer "In15.Cu")
		(net "FM_NCSI_OCP_V3_1_R_OE")
	)
	(segment
		(start 234.185968 -115.214908)
		(end 233.037888 -114.066828)
		(width 0.127)
		(layer "In15.Cu")
		(net "FM_NCSI_OCP_V3_1_R_OE")
	)
	(segment
		(start 268.538706 -119.865648)
		(end 249.18797 -119.865648)
		(width 0.127)
		(layer "In15.Cu")
		(net "FM_NCSI_OCP_V3_1_R_OE")
	)
	(segment
		(start 190.02121 -115.865148)
		(end 185.84545 -115.865148)
		(width 0.127)
		(layer "In15.Cu")
		(net "FM_NCSI_OCP_V3_1_R_OE")
	)
	(segment
		(start 185.84545 -115.865148)
		(end 185.755788 -115.775486)
		(width 0.127)
		(layer "In15.Cu")
		(net "FM_NCSI_OCP_V3_1_R_OE")
	)
	(segment
		(start 194.00139 -119.845328)
		(end 190.02121 -115.865148)
		(width 0.127)
		(layer "In15.Cu")
		(net "FM_NCSI_OCP_V3_1_R_OE")
	)
	(segment
		(start 222.14332 -114.066828)
		(end 220.99524 -115.214908)
		(width 0.127)
		(layer "In15.Cu")
		(net "FM_NCSI_OCP_V3_1_R_OE")
	)
	(segment
		(start 331.065378 -46.570646)
		(end 331.01661 -46.655228)
		(width 0.12954)
		(layer "F.Cu")
		(net "FM_MFG_MODE")
	)
	(segment
		(start 331.01661 -46.655228)
		(end 330.79436 -47.040546)
		(width 0.12954)
		(layer "F.Cu")
		(net "FM_MFG_MODE")
	)
	(via
		(at 314.366656 -35.865308)
		(size 0.6604)
		(drill 0.3302)
		(layers "F.Cu" "B.Cu")
		(net "FM_MFG_MODE")
	)
	(via
		(at 331.065378 -46.570646)
		(size 0.4572)
		(drill 0.2032)
		(layers "F.Cu" "B.Cu")
		(net "FM_MFG_MODE")
	)
	(segment
		(start 322.230496 -43.59275)
		(end 321.719194 -43.081448)
		(width 0.12954)
		(layer "B.Cu")
		(net "FM_MFG_MODE")
	)
	(segment
		(start 313.386978 -33.564068)
		(end 312.597292 -33.564068)
		(width 0.12954)
		(layer "B.Cu")
		(net "FM_MFG_MODE")
	)
	(segment
		(start 310.742584 -31.70936)
		(end 309.285132 -31.70936)
		(width 0.12954)
		(layer "B.Cu")
		(net "FM_MFG_MODE")
	)
	(segment
		(start 325.298054 -45.521372)
		(end 324.611238 -45.521372)
		(width 0.12954)
		(layer "B.Cu")
		(net "FM_MFG_MODE")
	)
	(segment
		(start 330.11491 -46.570646)
		(end 329.683872 -46.139608)
		(width 0.0889)
		(layer "B.Cu")
		(net "FM_MFG_MODE")
	)
	(segment
		(start 316.441074 -39.038276)
		(end 314.6044 -37.201602)
		(width 0.12954)
		(layer "B.Cu")
		(net "FM_MFG_MODE")
	)
	(segment
		(start 325.821548 -46.044866)
		(end 325.298054 -45.521372)
		(width 0.12954)
		(layer "B.Cu")
		(net "FM_MFG_MODE")
	)
	(segment
		(start 319.736216 -43.081448)
		(end 316.441074 -39.786306)
		(width 0.12954)
		(layer "B.Cu")
		(net "FM_MFG_MODE")
	)
	(segment
		(start 324.611238 -45.521372)
		(end 322.682616 -43.59275)
		(width 0.12954)
		(layer "B.Cu")
		(net "FM_MFG_MODE")
	)
	(segment
		(start 327.859898 -45.865796)
		(end 327.663556 -45.865796)
		(width 0.0889)
		(layer "B.Cu")
		(net "FM_MFG_MODE")
	)
	(segment
		(start 312.597292 -33.564068)
		(end 312.043572 -33.010348)
		(width 0.12954)
		(layer "B.Cu")
		(net "FM_MFG_MODE")
	)
	(segment
		(start 329.683872 -46.139608)
		(end 328.13371 -46.139608)
		(width 0.0889)
		(layer "B.Cu")
		(net "FM_MFG_MODE")
	)
	(segment
		(start 327.663556 -45.865796)
		(end 326.367648 -45.865796)
		(width 0.12954)
		(layer "B.Cu")
		(net "FM_MFG_MODE")
	)
	(segment
		(start 314.6044 -36.103052)
		(end 314.366656 -35.865308)
		(width 0.12954)
		(layer "B.Cu")
		(net "FM_MFG_MODE")
	)
	(segment
		(start 326.367648 -45.865796)
		(end 326.188578 -46.044866)
		(width 0.12954)
		(layer "B.Cu")
		(net "FM_MFG_MODE")
	)
	(segment
		(start 309.285132 -31.70936)
		(end 309.158132 -31.83636)
		(width 0.12954)
		(layer "B.Cu")
		(net "FM_MFG_MODE")
	)
	(segment
		(start 331.065378 -46.570646)
		(end 330.11491 -46.570646)
		(width 0.0889)
		(layer "B.Cu")
		(net "FM_MFG_MODE")
	)
	(segment
		(start 312.043572 -33.010348)
		(end 310.742584 -31.70936)
		(width 0.12954)
		(layer "B.Cu")
		(net "FM_MFG_MODE")
	)
	(segment
		(start 314.366656 -34.543746)
		(end 313.386978 -33.564068)
		(width 0.12954)
		(layer "B.Cu")
		(net "FM_MFG_MODE")
	)
	(segment
		(start 316.441074 -39.786306)
		(end 316.441074 -39.038276)
		(width 0.12954)
		(layer "B.Cu")
		(net "FM_MFG_MODE")
	)
	(segment
		(start 314.6044 -37.201602)
		(end 314.6044 -36.103052)
		(width 0.12954)
		(layer "B.Cu")
		(net "FM_MFG_MODE")
	)
	(segment
		(start 321.719194 -43.081448)
		(end 319.736216 -43.081448)
		(width 0.12954)
		(layer "B.Cu")
		(net "FM_MFG_MODE")
	)
	(segment
		(start 309.158132 -31.83636)
		(end 309.158132 -32.243268)
		(width 0.12954)
		(layer "B.Cu")
		(net "FM_MFG_MODE")
	)
	(segment
		(start 328.13371 -46.139608)
		(end 327.859898 -45.865796)
		(width 0.0889)
		(layer "B.Cu")
		(net "FM_MFG_MODE")
	)
	(segment
		(start 322.682616 -43.59275)
		(end 322.230496 -43.59275)
		(width 0.12954)
		(layer "B.Cu")
		(net "FM_MFG_MODE")
	)
	(segment
		(start 326.188578 -46.044866)
		(end 325.821548 -46.044866)
		(width 0.12954)
		(layer "B.Cu")
		(net "FM_MFG_MODE")
	)
	(segment
		(start 314.366656 -35.865308)
		(end 314.366656 -34.543746)
		(width 0.12954)
		(layer "B.Cu")
		(net "FM_MFG_MODE")
	)
	(segment
		(start 329.388724 -46.655228)
		(end 329.165966 -47.040546)
		(width 0.12954)
		(layer "F.Cu")
		(net "FM_ME_RCVR_N")
	)
	(segment
		(start 300.08068 -40.122348)
		(end 300.094904 -40.136572)
		(width 0.12954)
		(layer "F.Cu")
		(net "FM_ME_RCVR_N")
	)
	(segment
		(start 300.094904 -40.136572)
		(end 300.094904 -41.587674)
		(width 0.12954)
		(layer "F.Cu")
		(net "FM_ME_RCVR_N")
	)
	(segment
		(start 329.437746 -46.570646)
		(end 329.388724 -46.655228)
		(width 0.12954)
		(layer "F.Cu")
		(net "FM_ME_RCVR_N")
	)
	(via
		(at 300.08068 -40.122348)
		(size 0.508)
		(drill 0.254)
		(layers "F.Cu" "B.Cu")
		(net "FM_ME_RCVR_N")
	)
	(via
		(at 329.437746 -46.570646)
		(size 0.4572)
		(drill 0.2032)
		(layers "F.Cu" "B.Cu")
		(net "FM_ME_RCVR_N")
	)
	(segment
		(start 308.72684 -44.999148)
		(end 302.18888 -44.999148)
		(width 0.127)
		(layer "In6.Cu")
		(net "FM_ME_RCVR_N")
	)
	(segment
		(start 324.58914 -45.733208)
		(end 313.90082 -45.733208)
		(width 0.127)
		(layer "In6.Cu")
		(net "FM_ME_RCVR_N")
	)
	(segment
		(start 325.91248 -47.056548)
		(end 324.58914 -45.733208)
		(width 0.127)
		(layer "In6.Cu")
		(net "FM_ME_RCVR_N")
	)
	(segment
		(start 329.437746 -46.570646)
		(end 328.951844 -47.056548)
		(width 0.127)
		(layer "In6.Cu")
		(net "FM_ME_RCVR_N")
	)
	(segment
		(start 309.86476 -46.137068)
		(end 308.72684 -44.999148)
		(width 0.127)
		(layer "In6.Cu")
		(net "FM_ME_RCVR_N")
	)
	(segment
		(start 300.08068 -42.890948)
		(end 300.08068 -40.122348)
		(width 0.127)
		(layer "In6.Cu")
		(net "FM_ME_RCVR_N")
	)
	(segment
		(start 328.951844 -47.056548)
		(end 325.91248 -47.056548)
		(width 0.127)
		(layer "In6.Cu")
		(net "FM_ME_RCVR_N")
	)
	(segment
		(start 313.49696 -46.137068)
		(end 309.86476 -46.137068)
		(width 0.127)
		(layer "In6.Cu")
		(net "FM_ME_RCVR_N")
	)
	(segment
		(start 302.18888 -44.999148)
		(end 300.08068 -42.890948)
		(width 0.127)
		(layer "In6.Cu")
		(net "FM_ME_RCVR_N")
	)
	(segment
		(start 313.90082 -45.733208)
		(end 313.49696 -46.137068)
		(width 0.127)
		(layer "In6.Cu")
		(net "FM_ME_RCVR_N")
	)
	(segment
		(start 364.849664 -50.272188)
		(end 371.67947 -50.272188)
		(width 0.127)
		(layer "In15.Cu")
		(net "FM_ME_RCVR_N")
	)
	(segment
		(start 375.83491 -46.116748)
		(end 393.43711 -46.116748)
		(width 0.127)
		(layer "In15.Cu")
		(net "FM_ME_RCVR_N")
	)
	(segment
		(start 345.211146 -38.166548)
		(end 347.38056 -40.335962)
		(width 0.127)
		(layer "In15.Cu")
		(net "FM_ME_RCVR_N")
	)
	(segment
		(start 371.67947 -50.272188)
		(end 375.83491 -46.116748)
		(width 0.127)
		(layer "In15.Cu")
		(net "FM_ME_RCVR_N")
	)
	(segment
		(start 351.46742 -52.791868)
		(end 362.329984 -52.791868)
		(width 0.127)
		(layer "In15.Cu")
		(net "FM_ME_RCVR_N")
	)
	(segment
		(start 418.02304 -37.826188)
		(end 422.63568 -33.213548)
		(width 0.127)
		(layer "In15.Cu")
		(net "FM_ME_RCVR_N")
	)
	(segment
		(start 422.63568 -33.213548)
		(end 427.02734 -33.213548)
		(width 0.127)
		(layer "In15.Cu")
		(net "FM_ME_RCVR_N")
	)
	(segment
		(start 347.38056 -48.705008)
		(end 351.46742 -52.791868)
		(width 0.127)
		(layer "In15.Cu")
		(net "FM_ME_RCVR_N")
	)
	(segment
		(start 329.607926 -39.533068)
		(end 330.974446 -38.166548)
		(width 0.127)
		(layer "In15.Cu")
		(net "FM_ME_RCVR_N")
	)
	(segment
		(start 330.974446 -38.166548)
		(end 345.211146 -38.166548)
		(width 0.127)
		(layer "In15.Cu")
		(net "FM_ME_RCVR_N")
	)
	(segment
		(start 328.52106 -39.533068)
		(end 329.607926 -39.533068)
		(width 0.127)
		(layer "In15.Cu")
		(net "FM_ME_RCVR_N")
	)
	(segment
		(start 329.437746 -46.570646)
		(end 329.437746 -46.630082)
		(width 0.127)
		(layer "In15.Cu")
		(net "FM_ME_RCVR_N")
	)
	(segment
		(start 401.72767 -37.826188)
		(end 418.02304 -37.826188)
		(width 0.127)
		(layer "In15.Cu")
		(net "FM_ME_RCVR_N")
	)
	(segment
		(start 362.329984 -52.791868)
		(end 364.849664 -50.272188)
		(width 0.127)
		(layer "In15.Cu")
		(net "FM_ME_RCVR_N")
	)
	(segment
		(start 329.437746 -46.630082)
		(end 329.03668 -47.031148)
		(width 0.127)
		(layer "In15.Cu")
		(net "FM_ME_RCVR_N")
	)
	(segment
		(start 428.320962 -31.919926)
		(end 429.170084 -31.919926)
		(width 0.127)
		(layer "In15.Cu")
		(net "FM_ME_RCVR_N")
	)
	(segment
		(start 393.43711 -46.116748)
		(end 401.72767 -37.826188)
		(width 0.127)
		(layer "In15.Cu")
		(net "FM_ME_RCVR_N")
	)
	(segment
		(start 325.22668 -42.827448)
		(end 328.52106 -39.533068)
		(width 0.127)
		(layer "In15.Cu")
		(net "FM_ME_RCVR_N")
	)
	(segment
		(start 427.02734 -33.213548)
		(end 428.320962 -31.919926)
		(width 0.127)
		(layer "In15.Cu")
		(net "FM_ME_RCVR_N")
	)
	(segment
		(start 325.22668 -45.607478)
		(end 325.22668 -42.827448)
		(width 0.127)
		(layer "In15.Cu")
		(net "FM_ME_RCVR_N")
	)
	(segment
		(start 326.65035 -47.031148)
		(end 325.22668 -45.607478)
		(width 0.127)
		(layer "In15.Cu")
		(net "FM_ME_RCVR_N")
	)
	(segment
		(start 329.03668 -47.031148)
		(end 326.65035 -47.031148)
		(width 0.127)
		(layer "In15.Cu")
		(net "FM_ME_RCVR_N")
	)
	(segment
		(start 347.38056 -40.335962)
		(end 347.38056 -48.705008)
		(width 0.127)
		(layer "In15.Cu")
		(net "FM_ME_RCVR_N")
	)
	(segment
		(start 182.155592 -115.375436)
		(end 182.555642 -115.775486)
		(width 0.12954)
		(layer "F.Cu")
		(net "FM_ME_BT_DONE")
	)
	(segment
		(start 340.215474 -41.401746)
		(end 340.562946 -41.401746)
		(width 0.12954)
		(layer "F.Cu")
		(net "FM_ME_BT_DONE")
	)
	(segment
		(start 340.152482 -41.338754)
		(end 340.215474 -41.401746)
		(width 0.12954)
		(layer "F.Cu")
		(net "FM_ME_BT_DONE")
	)
	(segment
		(start 340.290658 -40.931846)
		(end 340.152482 -41.070022)
		(width 0.12954)
		(layer "F.Cu")
		(net "FM_ME_BT_DONE")
	)
	(segment
		(start 340.152482 -41.070022)
		(end 340.152482 -41.338754)
		(width 0.12954)
		(layer "F.Cu")
		(net "FM_ME_BT_DONE")
	)
	(via
		(at 330.25588 -121.249948)
		(size 0.508)
		(drill 0.254)
		(layers "F.Cu" "B.Cu")
		(net "FM_ME_BT_DONE")
	)
	(via
		(at 340.290658 -40.931846)
		(size 0.4572)
		(drill 0.2032)
		(layers "F.Cu" "B.Cu")
		(net "FM_ME_BT_DONE")
	)
	(via
		(at 182.555642 -115.775486)
		(size 0.4572)
		(drill 0.254)
		(layers "F.Cu" "B.Cu")
		(net "FM_ME_BT_DONE")
	)
	(via
		(at 340.228174 -39.29507)
		(size 0.6604)
		(drill 0.3302)
		(layers "F.Cu" "B.Cu")
		(net "FM_ME_BT_DONE")
	)
	(segment
		(start 339.814662 -40.45585)
		(end 339.814662 -39.708582)
		(width 0.12954)
		(layer "B.Cu")
		(net "FM_ME_BT_DONE")
	)
	(segment
		(start 340.571836 -38.951408)
		(end 341.64905 -38.951408)
		(width 0.12954)
		(layer "B.Cu")
		(net "FM_ME_BT_DONE")
	)
	(segment
		(start 340.290658 -40.931846)
		(end 339.814662 -40.45585)
		(width 0.12954)
		(layer "B.Cu")
		(net "FM_ME_BT_DONE")
	)
	(segment
		(start 341.64905 -38.951408)
		(end 342.037416 -38.563042)
		(width 0.12954)
		(layer "B.Cu")
		(net "FM_ME_BT_DONE")
	)
	(segment
		(start 340.228174 -39.29507)
		(end 340.571836 -38.951408)
		(width 0.12954)
		(layer "B.Cu")
		(net "FM_ME_BT_DONE")
	)
	(segment
		(start 339.814662 -39.708582)
		(end 340.228174 -39.29507)
		(width 0.12954)
		(layer "B.Cu")
		(net "FM_ME_BT_DONE")
	)
	(segment
		(start 342.037416 -38.563042)
		(end 342.037416 -37.974778)
		(width 0.12954)
		(layer "B.Cu")
		(net "FM_ME_BT_DONE")
	)
	(segment
		(start 340.290658 -40.931846)
		(end 339.80374 -41.418764)
		(width 0.127)
		(layer "In2.Cu")
		(net "FM_ME_BT_DONE")
	)
	(segment
		(start 339.011768 -48.61306)
		(end 338.506308 -49.11852)
		(width 0.127)
		(layer "In2.Cu")
		(net "FM_ME_BT_DONE")
	)
	(segment
		(start 331.1017 -120.404128)
		(end 330.25588 -121.249948)
		(width 0.127)
		(layer "In2.Cu")
		(net "FM_ME_BT_DONE")
	)
	(segment
		(start 339.80374 -41.418764)
		(end 339.80374 -44.888404)
		(width 0.127)
		(layer "In2.Cu")
		(net "FM_ME_BT_DONE")
	)
	(segment
		(start 338.506308 -51.524916)
		(end 339.03412 -52.052728)
		(width 0.127)
		(layer "In2.Cu")
		(net "FM_ME_BT_DONE")
	)
	(segment
		(start 337.145376 -71.608188)
		(end 337.02752 -71.608188)
		(width 0.127)
		(layer "In2.Cu")
		(net "FM_ME_BT_DONE")
	)
	(segment
		(start 339.80374 -44.888404)
		(end 339.011768 -45.680376)
		(width 0.127)
		(layer "In2.Cu")
		(net "FM_ME_BT_DONE")
	)
	(segment
		(start 333.24292 -75.392788)
		(end 333.24292 -77.859128)
		(width 0.127)
		(layer "In2.Cu")
		(net "FM_ME_BT_DONE")
	)
	(segment
		(start 339.471 -58.186828)
		(end 339.471 -69.282564)
		(width 0.127)
		(layer "In2.Cu")
		(net "FM_ME_BT_DONE")
	)
	(segment
		(start 339.011768 -45.680376)
		(end 339.011768 -48.61306)
		(width 0.127)
		(layer "In2.Cu")
		(net "FM_ME_BT_DONE")
	)
	(segment
		(start 333.24292 -77.859128)
		(end 331.1017 -80.000348)
		(width 0.127)
		(layer "In2.Cu")
		(net "FM_ME_BT_DONE")
	)
	(segment
		(start 331.1017 -80.000348)
		(end 331.1017 -120.404128)
		(width 0.127)
		(layer "In2.Cu")
		(net "FM_ME_BT_DONE")
	)
	(segment
		(start 339.471 -69.282564)
		(end 337.145376 -71.608188)
		(width 0.127)
		(layer "In2.Cu")
		(net "FM_ME_BT_DONE")
	)
	(segment
		(start 339.03412 -52.052728)
		(end 339.03412 -57.749948)
		(width 0.127)
		(layer "In2.Cu")
		(net "FM_ME_BT_DONE")
	)
	(segment
		(start 337.02752 -71.608188)
		(end 333.24292 -75.392788)
		(width 0.127)
		(layer "In2.Cu")
		(net "FM_ME_BT_DONE")
	)
	(segment
		(start 338.506308 -49.11852)
		(end 338.506308 -51.524916)
		(width 0.127)
		(layer "In2.Cu")
		(net "FM_ME_BT_DONE")
	)
	(segment
		(start 339.03412 -57.749948)
		(end 339.471 -58.186828)
		(width 0.127)
		(layer "In2.Cu")
		(net "FM_ME_BT_DONE")
	)
	(segment
		(start 323.95668 -122.215148)
		(end 325.42988 -120.741948)
		(width 0.127)
		(layer "In15.Cu")
		(net "FM_ME_BT_DONE")
	)
	(segment
		(start 248.454926 -125.291088)
		(end 250.527566 -123.218448)
		(width 0.127)
		(layer "In15.Cu")
		(net "FM_ME_BT_DONE")
	)
	(segment
		(start 182.954422 -117.56771)
		(end 183.169306 -117.782594)
		(width 0.127)
		(layer "In15.Cu")
		(net "FM_ME_BT_DONE")
	)
	(segment
		(start 325.42988 -120.741948)
		(end 327.36028 -120.741948)
		(width 0.127)
		(layer "In15.Cu")
		(net "FM_ME_BT_DONE")
	)
	(segment
		(start 327.36028 -120.741948)
		(end 328.35088 -121.732548)
		(width 0.127)
		(layer "In15.Cu")
		(net "FM_ME_BT_DONE")
	)
	(segment
		(start 186.06516 -119.380508)
		(end 186.94273 -120.258078)
		(width 0.127)
		(layer "In15.Cu")
		(net "FM_ME_BT_DONE")
	)
	(segment
		(start 190.842392 -123.543568)
		(end 193.997072 -126.698248)
		(width 0.127)
		(layer "In15.Cu")
		(net "FM_ME_BT_DONE")
	)
	(segment
		(start 217.029284 -124.419868)
		(end 220.530674 -120.918478)
		(width 0.127)
		(layer "In15.Cu")
		(net "FM_ME_BT_DONE")
	)
	(segment
		(start 184.805066 -119.380508)
		(end 186.06516 -119.380508)
		(width 0.127)
		(layer "In15.Cu")
		(net "FM_ME_BT_DONE")
	)
	(segment
		(start 220.530674 -120.918478)
		(end 228.40315 -120.918478)
		(width 0.127)
		(layer "In15.Cu")
		(net "FM_ME_BT_DONE")
	)
	(segment
		(start 320.34988 -120.741948)
		(end 321.82308 -122.215148)
		(width 0.127)
		(layer "In15.Cu")
		(net "FM_ME_BT_DONE")
	)
	(segment
		(start 186.94273 -120.258078)
		(end 186.94273 -120.832118)
		(width 0.127)
		(layer "In15.Cu")
		(net "FM_ME_BT_DONE")
	)
	(segment
		(start 282.745434 -123.218448)
		(end 285.221934 -120.741948)
		(width 0.127)
		(layer "In15.Cu")
		(net "FM_ME_BT_DONE")
	)
	(segment
		(start 183.169306 -117.782594)
		(end 183.518556 -117.782594)
		(width 0.127)
		(layer "In15.Cu")
		(net "FM_ME_BT_DONE")
	)
	(segment
		(start 232.81513 -121.599198)
		(end 233.46918 -122.253248)
		(width 0.127)
		(layer "In15.Cu")
		(net "FM_ME_BT_DONE")
	)
	(segment
		(start 208.59496 -124.419868)
		(end 217.029284 -124.419868)
		(width 0.127)
		(layer "In15.Cu")
		(net "FM_ME_BT_DONE")
	)
	(segment
		(start 328.35088 -121.732548)
		(end 329.77328 -121.732548)
		(width 0.127)
		(layer "In15.Cu")
		(net "FM_ME_BT_DONE")
	)
	(segment
		(start 245.344696 -125.291088)
		(end 248.454926 -125.291088)
		(width 0.127)
		(layer "In15.Cu")
		(net "FM_ME_BT_DONE")
	)
	(segment
		(start 184.318402 -118.58244)
		(end 184.56275 -118.826788)
		(width 0.127)
		(layer "In15.Cu")
		(net "FM_ME_BT_DONE")
	)
	(segment
		(start 183.76265 -118.338346)
		(end 184.006744 -118.58244)
		(width 0.127)
		(layer "In15.Cu")
		(net "FM_ME_BT_DONE")
	)
	(segment
		(start 228.40315 -120.918478)
		(end 229.08387 -121.599198)
		(width 0.127)
		(layer "In15.Cu")
		(net "FM_ME_BT_DONE")
	)
	(segment
		(start 193.997072 -126.698248)
		(end 206.31658 -126.698248)
		(width 0.127)
		(layer "In15.Cu")
		(net "FM_ME_BT_DONE")
	)
	(segment
		(start 183.76265 -118.026688)
		(end 183.76265 -118.338346)
		(width 0.127)
		(layer "In15.Cu")
		(net "FM_ME_BT_DONE")
	)
	(segment
		(start 229.08387 -121.599198)
		(end 232.81513 -121.599198)
		(width 0.127)
		(layer "In15.Cu")
		(net "FM_ME_BT_DONE")
	)
	(segment
		(start 189.65418 -123.543568)
		(end 190.842392 -123.543568)
		(width 0.127)
		(layer "In15.Cu")
		(net "FM_ME_BT_DONE")
	)
	(segment
		(start 206.31658 -126.698248)
		(end 208.59496 -124.419868)
		(width 0.127)
		(layer "In15.Cu")
		(net "FM_ME_BT_DONE")
	)
	(segment
		(start 285.221934 -120.741948)
		(end 320.34988 -120.741948)
		(width 0.127)
		(layer "In15.Cu")
		(net "FM_ME_BT_DONE")
	)
	(segment
		(start 184.56275 -118.826788)
		(end 184.56275 -119.138192)
		(width 0.127)
		(layer "In15.Cu")
		(net "FM_ME_BT_DONE")
	)
	(segment
		(start 182.954422 -116.174266)
		(end 182.954422 -117.56771)
		(width 0.127)
		(layer "In15.Cu")
		(net "FM_ME_BT_DONE")
	)
	(segment
		(start 250.527566 -123.218448)
		(end 282.745434 -123.218448)
		(width 0.127)
		(layer "In15.Cu")
		(net "FM_ME_BT_DONE")
	)
	(segment
		(start 183.518556 -117.782594)
		(end 183.76265 -118.026688)
		(width 0.127)
		(layer "In15.Cu")
		(net "FM_ME_BT_DONE")
	)
	(segment
		(start 242.306856 -122.253248)
		(end 245.344696 -125.291088)
		(width 0.127)
		(layer "In15.Cu")
		(net "FM_ME_BT_DONE")
	)
	(segment
		(start 184.56275 -119.138192)
		(end 184.805066 -119.380508)
		(width 0.127)
		(layer "In15.Cu")
		(net "FM_ME_BT_DONE")
	)
	(segment
		(start 182.555642 -115.775486)
		(end 182.954422 -116.174266)
		(width 0.127)
		(layer "In15.Cu")
		(net "FM_ME_BT_DONE")
	)
	(segment
		(start 321.82308 -122.215148)
		(end 323.95668 -122.215148)
		(width 0.127)
		(layer "In15.Cu")
		(net "FM_ME_BT_DONE")
	)
	(segment
		(start 329.77328 -121.732548)
		(end 330.25588 -121.249948)
		(width 0.127)
		(layer "In15.Cu")
		(net "FM_ME_BT_DONE")
	)
	(segment
		(start 186.94273 -120.832118)
		(end 189.65418 -123.543568)
		(width 0.127)
		(layer "In15.Cu")
		(net "FM_ME_BT_DONE")
	)
	(segment
		(start 184.006744 -118.58244)
		(end 184.318402 -118.58244)
		(width 0.127)
		(layer "In15.Cu")
		(net "FM_ME_BT_DONE")
	)
	(segment
		(start 233.46918 -122.253248)
		(end 242.306856 -122.253248)
		(width 0.127)
		(layer "In15.Cu")
		(net "FM_ME_BT_DONE")
	)
	(segment
		(start 335.140808 -41.401746)
		(end 335.67878 -41.401746)
		(width 0.12954)
		(layer "F.Cu")
		(net "FM_ME_AUTHN_FAIL")
	)
	(segment
		(start 185.355738 -110.575344)
		(end 185.755788 -110.175294)
		(width 0.12954)
		(layer "F.Cu")
		(net "FM_ME_AUTHN_FAIL")
	)
	(via
		(at 185.755788 -110.175294)
		(size 0.4572)
		(drill 0.254)
		(layers "F.Cu" "B.Cu")
		(net "FM_ME_AUTHN_FAIL")
	)
	(via
		(at 339.552026 -38.175692)
		(size 0.6604)
		(drill 0.3302)
		(layers "F.Cu" "B.Cu")
		(net "FM_ME_AUTHN_FAIL")
	)
	(via
		(at 329.06716 -111.989108)
		(size 0.508)
		(drill 0.254)
		(layers "F.Cu" "B.Cu")
		(net "FM_ME_AUTHN_FAIL")
	)
	(via
		(at 335.140808 -41.401746)
		(size 0.4572)
		(drill 0.2032)
		(layers "F.Cu" "B.Cu")
		(net "FM_ME_AUTHN_FAIL")
	)
	(segment
		(start 336.122772 -41.401746)
		(end 335.140808 -41.401746)
		(width 0.12954)
		(layer "B.Cu")
		(net "FM_ME_AUTHN_FAIL")
	)
	(segment
		(start 336.523838 -40.85209)
		(end 336.523838 -41.00068)
		(width 0.12954)
		(layer "B.Cu")
		(net "FM_ME_AUTHN_FAIL")
	)
	(segment
		(start 339.75294 -37.974778)
		(end 339.552026 -38.175692)
		(width 0.12954)
		(layer "B.Cu")
		(net "FM_ME_AUTHN_FAIL")
	)
	(segment
		(start 338.519516 -39.975028)
		(end 338.265516 -39.975028)
		(width 0.12954)
		(layer "B.Cu")
		(net "FM_ME_AUTHN_FAIL")
	)
	(segment
		(start 338.265516 -39.975028)
		(end 337.825334 -40.41521)
		(width 0.12954)
		(layer "B.Cu")
		(net "FM_ME_AUTHN_FAIL")
	)
	(segment
		(start 341.00135 -37.974778)
		(end 339.75294 -37.974778)
		(width 0.12954)
		(layer "B.Cu")
		(net "FM_ME_AUTHN_FAIL")
	)
	(segment
		(start 337.825334 -40.41521)
		(end 336.960718 -40.41521)
		(width 0.12954)
		(layer "B.Cu")
		(net "FM_ME_AUTHN_FAIL")
	)
	(segment
		(start 339.552026 -38.942518)
		(end 338.519516 -39.975028)
		(width 0.12954)
		(layer "B.Cu")
		(net "FM_ME_AUTHN_FAIL")
	)
	(segment
		(start 339.552026 -38.175692)
		(end 339.552026 -38.942518)
		(width 0.12954)
		(layer "B.Cu")
		(net "FM_ME_AUTHN_FAIL")
	)
	(segment
		(start 336.960718 -40.41521)
		(end 336.523838 -40.85209)
		(width 0.12954)
		(layer "B.Cu")
		(net "FM_ME_AUTHN_FAIL")
	)
	(segment
		(start 336.523838 -41.00068)
		(end 336.122772 -41.401746)
		(width 0.12954)
		(layer "B.Cu")
		(net "FM_ME_AUTHN_FAIL")
	)
	(segment
		(start 334.059784 -50.256186)
		(end 333.461106 -50.256186)
		(width 0.127)
		(layer "In2.Cu")
		(net "FM_ME_AUTHN_FAIL")
	)
	(segment
		(start 332.17866 -54.17947)
		(end 332.431898 -54.432708)
		(width 0.127)
		(layer "In2.Cu")
		(net "FM_ME_AUTHN_FAIL")
	)
	(segment
		(start 335.39938 -46.139608)
		(end 335.39938 -48.481488)
		(width 0.127)
		(layer "In2.Cu")
		(net "FM_ME_AUTHN_FAIL")
	)
	(segment
		(start 332.431898 -54.432708)
		(end 332.431898 -55.638192)
		(width 0.127)
		(layer "In2.Cu")
		(net "FM_ME_AUTHN_FAIL")
	)
	(segment
		(start 332.332076 -56.321452)
		(end 332.332076 -56.55183)
		(width 0.127)
		(layer "In2.Cu")
		(net "FM_ME_AUTHN_FAIL")
	)
	(segment
		(start 334.73136 -41.811194)
		(end 334.73136 -44.193968)
		(width 0.127)
		(layer "In2.Cu")
		(net "FM_ME_AUTHN_FAIL")
	)
	(segment
		(start 330.535788 -62.67831)
		(end 330.535788 -72.0852)
		(width 0.127)
		(layer "In2.Cu")
		(net "FM_ME_AUTHN_FAIL")
	)
	(segment
		(start 329.97648 -74.823828)
		(end 329.97648 -111.079788)
		(width 0.127)
		(layer "In2.Cu")
		(net "FM_ME_AUTHN_FAIL")
	)
	(segment
		(start 332.18628 -56.175656)
		(end 332.332076 -56.321452)
		(width 0.127)
		(layer "In2.Cu")
		(net "FM_ME_AUTHN_FAIL")
	)
	(segment
		(start 332.608936 -52.474622)
		(end 332.17866 -52.904898)
		(width 0.127)
		(layer "In2.Cu")
		(net "FM_ME_AUTHN_FAIL")
	)
	(segment
		(start 329.42022 -74.267568)
		(end 329.97648 -74.823828)
		(width 0.127)
		(layer "In2.Cu")
		(net "FM_ME_AUTHN_FAIL")
	)
	(segment
		(start 331.257402 -61.956696)
		(end 330.535788 -62.67831)
		(width 0.127)
		(layer "In2.Cu")
		(net "FM_ME_AUTHN_FAIL")
	)
	(segment
		(start 331.257402 -57.626504)
		(end 331.257402 -61.956696)
		(width 0.127)
		(layer "In2.Cu")
		(net "FM_ME_AUTHN_FAIL")
	)
	(segment
		(start 329.42022 -73.200768)
		(end 329.42022 -74.267568)
		(width 0.127)
		(layer "In2.Cu")
		(net "FM_ME_AUTHN_FAIL")
	)
	(segment
		(start 330.535788 -72.0852)
		(end 329.42022 -73.200768)
		(width 0.127)
		(layer "In2.Cu")
		(net "FM_ME_AUTHN_FAIL")
	)
	(segment
		(start 334.73136 -44.193968)
		(end 334.505808 -44.41952)
		(width 0.127)
		(layer "In2.Cu")
		(net "FM_ME_AUTHN_FAIL")
	)
	(segment
		(start 332.431898 -55.638192)
		(end 332.18628 -55.88381)
		(width 0.127)
		(layer "In2.Cu")
		(net "FM_ME_AUTHN_FAIL")
	)
	(segment
		(start 333.461106 -50.256186)
		(end 332.608936 -51.108356)
		(width 0.127)
		(layer "In2.Cu")
		(net "FM_ME_AUTHN_FAIL")
	)
	(segment
		(start 332.17866 -52.904898)
		(end 332.17866 -54.17947)
		(width 0.127)
		(layer "In2.Cu")
		(net "FM_ME_AUTHN_FAIL")
	)
	(segment
		(start 329.97648 -111.079788)
		(end 329.06716 -111.989108)
		(width 0.127)
		(layer "In2.Cu")
		(net "FM_ME_AUTHN_FAIL")
	)
	(segment
		(start 334.505808 -45.246036)
		(end 335.39938 -46.139608)
		(width 0.127)
		(layer "In2.Cu")
		(net "FM_ME_AUTHN_FAIL")
	)
	(segment
		(start 335.140808 -41.401746)
		(end 334.73136 -41.811194)
		(width 0.127)
		(layer "In2.Cu")
		(net "FM_ME_AUTHN_FAIL")
	)
	(segment
		(start 334.49768 -49.383188)
		(end 334.49768 -49.81829)
		(width 0.127)
		(layer "In2.Cu")
		(net "FM_ME_AUTHN_FAIL")
	)
	(segment
		(start 334.49768 -49.81829)
		(end 334.059784 -50.256186)
		(width 0.127)
		(layer "In2.Cu")
		(net "FM_ME_AUTHN_FAIL")
	)
	(segment
		(start 332.332076 -56.55183)
		(end 331.257402 -57.626504)
		(width 0.127)
		(layer "In2.Cu")
		(net "FM_ME_AUTHN_FAIL")
	)
	(segment
		(start 332.608936 -51.108356)
		(end 332.608936 -52.474622)
		(width 0.127)
		(layer "In2.Cu")
		(net "FM_ME_AUTHN_FAIL")
	)
	(segment
		(start 334.505808 -44.41952)
		(end 334.505808 -45.246036)
		(width 0.127)
		(layer "In2.Cu")
		(net "FM_ME_AUTHN_FAIL")
	)
	(segment
		(start 332.18628 -55.88381)
		(end 332.18628 -56.175656)
		(width 0.127)
		(layer "In2.Cu")
		(net "FM_ME_AUTHN_FAIL")
	)
	(segment
		(start 335.39938 -48.481488)
		(end 334.49768 -49.383188)
		(width 0.127)
		(layer "In2.Cu")
		(net "FM_ME_AUTHN_FAIL")
	)
	(segment
		(start 193.42735 -105.425748)
		(end 199.59574 -105.425748)
		(width 0.127)
		(layer "In15.Cu")
		(net "FM_ME_AUTHN_FAIL")
	)
	(segment
		(start 280.481786 -114.823748)
		(end 283.316426 -111.989108)
		(width 0.127)
		(layer "In15.Cu")
		(net "FM_ME_AUTHN_FAIL")
	)
	(segment
		(start 186.461654 -109.931708)
		(end 188.92139 -109.931708)
		(width 0.127)
		(layer "In15.Cu")
		(net "FM_ME_AUTHN_FAIL")
	)
	(segment
		(start 211.4296 -102.944676)
		(end 219.179648 -102.944676)
		(width 0.127)
		(layer "In15.Cu")
		(net "FM_ME_AUTHN_FAIL")
	)
	(segment
		(start 185.755788 -110.175294)
		(end 186.218068 -110.175294)
		(width 0.127)
		(layer "In15.Cu")
		(net "FM_ME_AUTHN_FAIL")
	)
	(segment
		(start 208.580228 -103.42626)
		(end 210.948016 -103.42626)
		(width 0.127)
		(layer "In15.Cu")
		(net "FM_ME_AUTHN_FAIL")
	)
	(segment
		(start 188.92139 -109.931708)
		(end 193.42735 -105.425748)
		(width 0.127)
		(layer "In15.Cu")
		(net "FM_ME_AUTHN_FAIL")
	)
	(segment
		(start 219.54744 -103.312468)
		(end 231.508808 -103.312468)
		(width 0.127)
		(layer "In15.Cu")
		(net "FM_ME_AUTHN_FAIL")
	)
	(segment
		(start 200.580752 -106.41076)
		(end 205.595728 -106.41076)
		(width 0.127)
		(layer "In15.Cu")
		(net "FM_ME_AUTHN_FAIL")
	)
	(segment
		(start 251.013722 -116.512848)
		(end 267.14831 -116.512848)
		(width 0.127)
		(layer "In15.Cu")
		(net "FM_ME_AUTHN_FAIL")
	)
	(segment
		(start 283.316426 -111.989108)
		(end 329.06716 -111.989108)
		(width 0.127)
		(layer "In15.Cu")
		(net "FM_ME_AUTHN_FAIL")
	)
	(segment
		(start 210.948016 -103.42626)
		(end 211.4296 -102.944676)
		(width 0.127)
		(layer "In15.Cu")
		(net "FM_ME_AUTHN_FAIL")
	)
	(segment
		(start 205.595728 -106.41076)
		(end 208.580228 -103.42626)
		(width 0.127)
		(layer "In15.Cu")
		(net "FM_ME_AUTHN_FAIL")
	)
	(segment
		(start 199.59574 -105.425748)
		(end 200.580752 -106.41076)
		(width 0.127)
		(layer "In15.Cu")
		(net "FM_ME_AUTHN_FAIL")
	)
	(segment
		(start 186.218068 -110.175294)
		(end 186.461654 -109.931708)
		(width 0.127)
		(layer "In15.Cu")
		(net "FM_ME_AUTHN_FAIL")
	)
	(segment
		(start 231.508808 -103.312468)
		(end 234.80776 -106.61142)
		(width 0.127)
		(layer "In15.Cu")
		(net "FM_ME_AUTHN_FAIL")
	)
	(segment
		(start 267.14831 -116.512848)
		(end 268.83741 -114.823748)
		(width 0.127)
		(layer "In15.Cu")
		(net "FM_ME_AUTHN_FAIL")
	)
	(segment
		(start 268.83741 -114.823748)
		(end 280.481786 -114.823748)
		(width 0.127)
		(layer "In15.Cu")
		(net "FM_ME_AUTHN_FAIL")
	)
	(segment
		(start 241.112294 -106.61142)
		(end 251.013722 -116.512848)
		(width 0.127)
		(layer "In15.Cu")
		(net "FM_ME_AUTHN_FAIL")
	)
	(segment
		(start 219.179648 -102.944676)
		(end 219.54744 -103.312468)
		(width 0.127)
		(layer "In15.Cu")
		(net "FM_ME_AUTHN_FAIL")
	)
	(segment
		(start 234.80776 -106.61142)
		(end 241.112294 -106.61142)
		(width 0.127)
		(layer "In15.Cu")
		(net "FM_ME_AUTHN_FAIL")
	)
	(segment
		(start 180.37683 -39.969948)
		(end 180.37683 -39.600124)
		(width 0.12954)
		(layer "F.Cu")
		(net "FM_M2_SSD_0_PEDET")
	)
	(segment
		(start 180.37683 -39.600124)
		(end 180.4543 -39.522654)
		(width 0.12954)
		(layer "F.Cu")
		(net "FM_M2_SSD_0_PEDET")
	)
	(segment
		(start 179.892452 -39.299896)
		(end 177.108104 -39.299896)
		(width 0.12954)
		(layer "F.Cu")
		(net "FM_M2_SSD_0_PEDET")
	)
	(segment
		(start 180.37683 -41.112948)
		(end 180.37683 -39.969948)
		(width 0.12954)
		(layer "F.Cu")
		(net "FM_M2_SSD_0_PEDET")
	)
	(segment
		(start 180.4543 -39.522654)
		(end 180.4543 -38.738048)
		(width 0.12954)
		(layer "F.Cu")
		(net "FM_M2_SSD_0_PEDET")
	)
	(segment
		(start 180.4543 -38.738048)
		(end 179.892452 -39.299896)
		(width 0.12954)
		(layer "F.Cu")
		(net "FM_M2_SSD_0_PEDET")
	)
	(via
		(at 180.4543 -38.738048)
		(size 0.762)
		(drill 0.381)
		(layers "F.Cu" "B.Cu")
		(net "FM_M2_SSD_0_PEDET")
	)
	(segment
		(start 322.91401 -56.058054)
		(end 322.281296 -56.690768)
		(width 0.12954)
		(layer "F.Cu")
		(net "FM_LT_KEY_DOWNGRADE_N")
	)
	(segment
		(start 322.281296 -56.690768)
		(end 321.005454 -56.690768)
		(width 0.12954)
		(layer "F.Cu")
		(net "FM_LT_KEY_DOWNGRADE_N")
	)
	(segment
		(start 323.501766 -55.988458)
		(end 324.927468 -54.562502)
		(width 0.0889)
		(layer "F.Cu")
		(net "FM_LT_KEY_DOWNGRADE_N")
	)
	(segment
		(start 327.081388 -54.747668)
		(end 327.16978 -54.7116)
		(width 0.0889)
		(layer "F.Cu")
		(net "FM_LT_KEY_DOWNGRADE_N")
	)
	(segment
		(start 327.467976 -54.453028)
		(end 327.829926 -54.453028)
		(width 0.0889)
		(layer "F.Cu")
		(net "FM_LT_KEY_DOWNGRADE_N")
	)
	(segment
		(start 322.91401 -56.058054)
		(end 323.43217 -56.058054)
		(width 0.12954)
		(layer "F.Cu")
		(net "FM_LT_KEY_DOWNGRADE_N")
	)
	(segment
		(start 326.716644 -54.65445)
		(end 326.840342 -54.736746)
		(width 0.0889)
		(layer "F.Cu")
		(net "FM_LT_KEY_DOWNGRADE_N")
	)
	(segment
		(start 326.840342 -54.736746)
		(end 326.856852 -54.747668)
		(width 0.0889)
		(layer "F.Cu")
		(net "FM_LT_KEY_DOWNGRADE_N")
	)
	(segment
		(start 323.43217 -56.058054)
		(end 323.501766 -55.988458)
		(width 0.12954)
		(layer "F.Cu")
		(net "FM_LT_KEY_DOWNGRADE_N")
	)
	(segment
		(start 326.533002 -54.645814)
		(end 326.716644 -54.65445)
		(width 0.0889)
		(layer "F.Cu")
		(net "FM_LT_KEY_DOWNGRADE_N")
	)
	(segment
		(start 325.304404 -54.562502)
		(end 325.42988 -54.687978)
		(width 0.0889)
		(layer "F.Cu")
		(net "FM_LT_KEY_DOWNGRADE_N")
	)
	(segment
		(start 321.005454 -56.690768)
		(end 320.700654 -56.817006)
		(width 0.12954)
		(layer "F.Cu")
		(net "FM_LT_KEY_DOWNGRADE_N")
	)
	(segment
		(start 320.700654 -56.817006)
		(end 320.590672 -56.926988)
		(width 0.12954)
		(layer "F.Cu")
		(net "FM_LT_KEY_DOWNGRADE_N")
	)
	(segment
		(start 326.997314 -54.781958)
		(end 327.081388 -54.747668)
		(width 0.0889)
		(layer "F.Cu")
		(net "FM_LT_KEY_DOWNGRADE_N")
	)
	(segment
		(start 327.460102 -54.460902)
		(end 327.467976 -54.453028)
		(width 0.0889)
		(layer "F.Cu")
		(net "FM_LT_KEY_DOWNGRADE_N")
	)
	(segment
		(start 326.916034 -54.787038)
		(end 326.997314 -54.781958)
		(width 0.0889)
		(layer "F.Cu")
		(net "FM_LT_KEY_DOWNGRADE_N")
	)
	(segment
		(start 320.590672 -56.926988)
		(end 320.590672 -57.267348)
		(width 0.12954)
		(layer "F.Cu")
		(net "FM_LT_KEY_DOWNGRADE_N")
	)
	(segment
		(start 326.319896 -54.687978)
		(end 326.533002 -54.645814)
		(width 0.0889)
		(layer "F.Cu")
		(net "FM_LT_KEY_DOWNGRADE_N")
	)
	(segment
		(start 327.16978 -54.7116)
		(end 327.460102 -54.460902)
		(width 0.0889)
		(layer "F.Cu")
		(net "FM_LT_KEY_DOWNGRADE_N")
	)
	(segment
		(start 325.42988 -54.687978)
		(end 326.319896 -54.687978)
		(width 0.0889)
		(layer "F.Cu")
		(net "FM_LT_KEY_DOWNGRADE_N")
	)
	(segment
		(start 326.856852 -54.747668)
		(end 326.916034 -54.787038)
		(width 0.0889)
		(layer "F.Cu")
		(net "FM_LT_KEY_DOWNGRADE_N")
	)
	(segment
		(start 324.927468 -54.562502)
		(end 325.304404 -54.562502)
		(width 0.0889)
		(layer "F.Cu")
		(net "FM_LT_KEY_DOWNGRADE_N")
	)
	(via
		(at 322.91401 -56.058054)
		(size 0.508)
		(drill 0.254)
		(layers "F.Cu" "B.Cu")
		(net "FM_LT_KEY_DOWNGRADE_N")
	)
	(segment
		(start 169.55389 -28.044648)
		(end 167.879014 -28.044648)
		(width 0.12954)
		(layer "F.Cu")
		(net "FM_LPC_ESPI_SEL")
	)
	(segment
		(start 174.066962 -17.66443)
		(end 174.18812 -17.785588)
		(width 0.12954)
		(layer "F.Cu")
		(net "FM_LPC_ESPI_SEL")
	)
	(segment
		(start 169.57294 -28.025598)
		(end 169.55389 -28.044648)
		(width 0.12954)
		(layer "F.Cu")
		(net "FM_LPC_ESPI_SEL")
	)
	(segment
		(start 171.12488 -28.031948)
		(end 169.57929 -28.031948)
		(width 0.12954)
		(layer "F.Cu")
		(net "FM_LPC_ESPI_SEL")
	)
	(segment
		(start 174.066962 -16.550132)
		(end 174.066962 -17.66443)
		(width 0.12954)
		(layer "F.Cu")
		(net "FM_LPC_ESPI_SEL")
	)
	(segment
		(start 169.57929 -28.031948)
		(end 169.57294 -28.025598)
		(width 0.12954)
		(layer "F.Cu")
		(net "FM_LPC_ESPI_SEL")
	)
	(via
		(at 174.18812 -17.785588)
		(size 0.508)
		(drill 0.254)
		(layers "F.Cu" "B.Cu")
		(net "FM_LPC_ESPI_SEL")
	)
	(via
		(at 171.12488 -28.031948)
		(size 0.508)
		(drill 0.254)
		(layers "F.Cu" "B.Cu")
		(net "FM_LPC_ESPI_SEL")
	)
	(segment
		(start 174.393352 -22.164548)
		(end 173.377352 -22.164548)
		(width 0.12954)
		(layer "B.Cu")
		(net "FM_LPC_ESPI_SEL")
	)
	(segment
		(start 174.18812 -18.989548)
		(end 175.02378 -19.825208)
		(width 0.12954)
		(layer "B.Cu")
		(net "FM_LPC_ESPI_SEL")
	)
	(segment
		(start 175.02378 -19.825208)
		(end 175.02378 -20.521168)
		(width 0.12954)
		(layer "B.Cu")
		(net "FM_LPC_ESPI_SEL")
	)
	(segment
		(start 171.977304 -22.164548)
		(end 171.607988 -22.533864)
		(width 0.12954)
		(layer "B.Cu")
		(net "FM_LPC_ESPI_SEL")
	)
	(segment
		(start 174.18812 -17.785588)
		(end 174.18812 -18.989548)
		(width 0.12954)
		(layer "B.Cu")
		(net "FM_LPC_ESPI_SEL")
	)
	(segment
		(start 175.02378 -20.521168)
		(end 174.393352 -21.151596)
		(width 0.12954)
		(layer "B.Cu")
		(net "FM_LPC_ESPI_SEL")
	)
	(segment
		(start 173.377352 -22.164548)
		(end 171.977304 -22.164548)
		(width 0.12954)
		(layer "B.Cu")
		(net "FM_LPC_ESPI_SEL")
	)
	(segment
		(start 174.393352 -21.151596)
		(end 174.393352 -22.164548)
		(width 0.12954)
		(layer "B.Cu")
		(net "FM_LPC_ESPI_SEL")
	)
	(segment
		(start 171.607988 -27.54884)
		(end 171.12488 -28.031948)
		(width 0.12954)
		(layer "B.Cu")
		(net "FM_LPC_ESPI_SEL")
	)
	(segment
		(start 171.607988 -22.533864)
		(end 171.607988 -27.54884)
		(width 0.12954)
		(layer "B.Cu")
		(net "FM_LPC_ESPI_SEL")
	)
	(segment
		(start 195.19646 -90.155268)
		(end 195.06184 -90.289888)
		(width 0.12954)
		(layer "F.Cu")
		(net "FM_JTAG_TCK_MUX_SEL_R")
	)
	(segment
		(start 195.06184 -90.289888)
		(end 195.06184 -92.432378)
		(width 0.12954)
		(layer "F.Cu")
		(net "FM_JTAG_TCK_MUX_SEL_R")
	)
	(segment
		(start 182.955692 -117.775482)
		(end 183.355742 -118.175532)
		(width 0.12954)
		(layer "F.Cu")
		(net "FM_JTAG_TCK_MUX_SEL_R")
	)
	(via
		(at 195.19646 -90.155268)
		(size 0.508)
		(drill 0.254)
		(layers "F.Cu" "B.Cu")
		(net "FM_JTAG_TCK_MUX_SEL_R")
	)
	(via
		(at 183.355742 -118.175532)
		(size 0.4572)
		(drill 0.254)
		(layers "F.Cu" "B.Cu")
		(net "FM_JTAG_TCK_MUX_SEL_R")
	)
	(segment
		(start 191.0842 -97.961704)
		(end 190.244476 -98.801428)
		(width 0.127)
		(layer "In13.Cu")
		(net "FM_JTAG_TCK_MUX_SEL_R")
	)
	(segment
		(start 187.386722 -100.508308)
		(end 186.009534 -100.508308)
		(width 0.127)
		(layer "In13.Cu")
		(net "FM_JTAG_TCK_MUX_SEL_R")
	)
	(segment
		(start 191.0842 -94.605348)
		(end 191.0842 -97.961704)
		(width 0.127)
		(layer "In13.Cu")
		(net "FM_JTAG_TCK_MUX_SEL_R")
	)
	(segment
		(start 190.244476 -98.801428)
		(end 189.093602 -98.801428)
		(width 0.127)
		(layer "In13.Cu")
		(net "FM_JTAG_TCK_MUX_SEL_R")
	)
	(segment
		(start 189.093602 -98.801428)
		(end 187.386722 -100.508308)
		(width 0.127)
		(layer "In13.Cu")
		(net "FM_JTAG_TCK_MUX_SEL_R")
	)
	(segment
		(start 183.75122 -104.943148)
		(end 183.75122 -117.780054)
		(width 0.127)
		(layer "In13.Cu")
		(net "FM_JTAG_TCK_MUX_SEL_R")
	)
	(segment
		(start 183.75122 -117.780054)
		(end 183.355742 -118.175532)
		(width 0.127)
		(layer "In13.Cu")
		(net "FM_JTAG_TCK_MUX_SEL_R")
	)
	(segment
		(start 185.23966 -103.454708)
		(end 183.75122 -104.943148)
		(width 0.127)
		(layer "In13.Cu")
		(net "FM_JTAG_TCK_MUX_SEL_R")
	)
	(segment
		(start 185.23966 -101.278182)
		(end 185.23966 -103.454708)
		(width 0.127)
		(layer "In13.Cu")
		(net "FM_JTAG_TCK_MUX_SEL_R")
	)
	(segment
		(start 186.009534 -100.508308)
		(end 185.23966 -101.278182)
		(width 0.127)
		(layer "In13.Cu")
		(net "FM_JTAG_TCK_MUX_SEL_R")
	)
	(segment
		(start 195.19646 -90.155268)
		(end 195.19646 -90.493088)
		(width 0.127)
		(layer "In13.Cu")
		(net "FM_JTAG_TCK_MUX_SEL_R")
	)
	(segment
		(start 195.19646 -90.493088)
		(end 191.0842 -94.605348)
		(width 0.127)
		(layer "In13.Cu")
		(net "FM_JTAG_TCK_MUX_SEL_R")
	)
	(segment
		(start 107.125008 -61.102748)
		(end 107.65663 -61.102748)
		(width 0.12954)
		(layer "F.Cu")
		(net "FM_JTAG_TCK_MUX_SEL")
	)
	(segment
		(start 105.931208 -60.77839)
		(end 106.80065 -60.77839)
		(width 0.12954)
		(layer "F.Cu")
		(net "FM_JTAG_TCK_MUX_SEL")
	)
	(segment
		(start 195.06184 -93.232478)
		(end 195.06184 -93.894148)
		(width 0.12954)
		(layer "F.Cu")
		(net "FM_JTAG_TCK_MUX_SEL")
	)
	(segment
		(start 106.871008 -60.848748)
		(end 107.125008 -61.102748)
		(width 0.12954)
		(layer "F.Cu")
		(net "FM_JTAG_TCK_MUX_SEL")
	)
	(segment
		(start 106.80065 -60.77839)
		(end 106.871008 -60.848748)
		(width 0.12954)
		(layer "F.Cu")
		(net "FM_JTAG_TCK_MUX_SEL")
	)
	(via
		(at 195.06184 -93.894148)
		(size 0.508)
		(drill 0.254)
		(layers "F.Cu" "B.Cu")
		(net "FM_JTAG_TCK_MUX_SEL")
	)
	(via
		(at 106.871008 -60.848748)
		(size 0.508)
		(drill 0.254)
		(layers "F.Cu" "B.Cu")
		(net "FM_JTAG_TCK_MUX_SEL")
	)
	(segment
		(start 135.7376 -72.126348)
		(end 148.0566 -72.126348)
		(width 0.127)
		(layer "In15.Cu")
		(net "FM_JTAG_TCK_MUX_SEL")
	)
	(segment
		(start 111.9632 -67.478148)
		(end 131.0894 -67.478148)
		(width 0.127)
		(layer "In15.Cu")
		(net "FM_JTAG_TCK_MUX_SEL")
	)
	(segment
		(start 148.8948 -71.288148)
		(end 162.941 -71.288148)
		(width 0.127)
		(layer "In15.Cu")
		(net "FM_JTAG_TCK_MUX_SEL")
	)
	(segment
		(start 189.55004 -88.382348)
		(end 195.06184 -93.894148)
		(width 0.127)
		(layer "In15.Cu")
		(net "FM_JTAG_TCK_MUX_SEL")
	)
	(segment
		(start 106.871008 -60.848748)
		(end 107.7214 -61.69914)
		(width 0.127)
		(layer "In15.Cu")
		(net "FM_JTAG_TCK_MUX_SEL")
	)
	(segment
		(start 162.941 -71.288148)
		(end 180.0352 -88.382348)
		(width 0.127)
		(layer "In15.Cu")
		(net "FM_JTAG_TCK_MUX_SEL")
	)
	(segment
		(start 107.7214 -61.69914)
		(end 107.7214 -63.236348)
		(width 0.127)
		(layer "In15.Cu")
		(net "FM_JTAG_TCK_MUX_SEL")
	)
	(segment
		(start 180.0352 -88.382348)
		(end 189.55004 -88.382348)
		(width 0.127)
		(layer "In15.Cu")
		(net "FM_JTAG_TCK_MUX_SEL")
	)
	(segment
		(start 148.0566 -72.126348)
		(end 148.8948 -71.288148)
		(width 0.127)
		(layer "In15.Cu")
		(net "FM_JTAG_TCK_MUX_SEL")
	)
	(segment
		(start 131.0894 -67.478148)
		(end 135.7376 -72.126348)
		(width 0.127)
		(layer "In15.Cu")
		(net "FM_JTAG_TCK_MUX_SEL")
	)
	(segment
		(start 107.7214 -63.236348)
		(end 111.9632 -67.478148)
		(width 0.127)
		(layer "In15.Cu")
		(net "FM_JTAG_TCK_MUX_SEL")
	)
	(segment
		(start 330.79436 -41.401746)
		(end 330.254102 -41.401746)
		(width 0.12954)
		(layer "F.Cu")
		(net "FM_JTAG_ODT_DISABLE")
	)
	(via
		(at 330.254102 -41.401746)
		(size 0.4572)
		(drill 0.2032)
		(layers "F.Cu" "B.Cu")
		(net "FM_JTAG_ODT_DISABLE")
	)
	(via
		(at 327.992994 -38.626542)
		(size 0.6604)
		(drill 0.3302)
		(layers "F.Cu" "B.Cu")
		(net "FM_JTAG_ODT_DISABLE")
	)
	(segment
		(start 327.723754 -38.120574)
		(end 326.712072 -37.108892)
		(width 0.12954)
		(layer "B.Cu")
		(net "FM_JTAG_ODT_DISABLE")
	)
	(segment
		(start 326.00519 -29.24302)
		(end 325.61657 -28.8544)
		(width 0.12954)
		(layer "B.Cu")
		(net "FM_JTAG_ODT_DISABLE")
	)
	(segment
		(start 328.245216 -39.64432)
		(end 328.13244 -39.531544)
		(width 0.12954)
		(layer "B.Cu")
		(net "FM_JTAG_ODT_DISABLE")
	)
	(segment
		(start 329.097894 -40.744648)
		(end 329.085956 -40.744648)
		(width 0.0889)
		(layer "B.Cu")
		(net "FM_JTAG_ODT_DISABLE")
	)
	(segment
		(start 329.88758 -41.049702)
		(end 329.781408 -40.773858)
		(width 0.0889)
		(layer "B.Cu")
		(net "FM_JTAG_ODT_DISABLE")
	)
	(segment
		(start 328.13244 -39.531544)
		(end 328.13244 -38.963346)
		(width 0.12954)
		(layer "B.Cu")
		(net "FM_JTAG_ODT_DISABLE")
	)
	(segment
		(start 328.13244 -38.963346)
		(end 327.992994 -38.626542)
		(width 0.12954)
		(layer "B.Cu")
		(net "FM_JTAG_ODT_DISABLE")
	)
	(segment
		(start 328.42327 -40.836596)
		(end 328.245216 -40.658542)
		(width 0.0889)
		(layer "B.Cu")
		(net "FM_JTAG_ODT_DISABLE")
	)
	(segment
		(start 329.440794 -40.55745)
		(end 329.440286 -40.557196)
		(width 0.0889)
		(layer "B.Cu")
		(net "FM_JTAG_ODT_DISABLE")
	)
	(segment
		(start 326.95388 -35.446462)
		(end 326.95388 -34.262822)
		(width 0.12954)
		(layer "B.Cu")
		(net "FM_JTAG_ODT_DISABLE")
	)
	(segment
		(start 327.180194 -35.672776)
		(end 326.95388 -35.446462)
		(width 0.12954)
		(layer "B.Cu")
		(net "FM_JTAG_ODT_DISABLE")
	)
	(segment
		(start 325.61657 -28.8544)
		(end 324.98919 -28.8544)
		(width 0.12954)
		(layer "B.Cu")
		(net "FM_JTAG_ODT_DISABLE")
	)
	(segment
		(start 326.95388 -34.262822)
		(end 327.760076 -33.456626)
		(width 0.12954)
		(layer "B.Cu")
		(net "FM_JTAG_ODT_DISABLE")
	)
	(segment
		(start 327.760076 -33.456626)
		(end 327.760076 -31.459932)
		(width 0.12954)
		(layer "B.Cu")
		(net "FM_JTAG_ODT_DISABLE")
	)
	(segment
		(start 326.00519 -29.7053)
		(end 326.00519 -29.24302)
		(width 0.12954)
		(layer "B.Cu")
		(net "FM_JTAG_ODT_DISABLE")
	)
	(segment
		(start 329.781408 -40.773858)
		(end 329.764898 -40.744648)
		(width 0.0889)
		(layer "B.Cu")
		(net "FM_JTAG_ODT_DISABLE")
	)
	(segment
		(start 329.164188 -40.678354)
		(end 329.097894 -40.744648)
		(width 0.0889)
		(layer "B.Cu")
		(net "FM_JTAG_ODT_DISABLE")
	)
	(segment
		(start 330.254102 -41.401746)
		(end 329.88758 -41.049702)
		(width 0.0889)
		(layer "B.Cu")
		(net "FM_JTAG_ODT_DISABLE")
	)
	(segment
		(start 326.712072 -36.66871)
		(end 327.180194 -36.200588)
		(width 0.12954)
		(layer "B.Cu")
		(net "FM_JTAG_ODT_DISABLE")
	)
	(segment
		(start 328.245216 -40.091868)
		(end 328.245216 -39.64432)
		(width 0.12954)
		(layer "B.Cu")
		(net "FM_JTAG_ODT_DISABLE")
	)
	(segment
		(start 329.085956 -40.744648)
		(end 328.994008 -40.836596)
		(width 0.0889)
		(layer "B.Cu")
		(net "FM_JTAG_ODT_DISABLE")
	)
	(segment
		(start 327.992994 -38.626542)
		(end 327.891394 -38.524942)
		(width 0.12954)
		(layer "B.Cu")
		(net "FM_JTAG_ODT_DISABLE")
	)
	(segment
		(start 327.760076 -31.459932)
		(end 326.00519 -29.7053)
		(width 0.12954)
		(layer "B.Cu")
		(net "FM_JTAG_ODT_DISABLE")
	)
	(segment
		(start 327.180194 -36.200588)
		(end 327.180194 -35.672776)
		(width 0.12954)
		(layer "B.Cu")
		(net "FM_JTAG_ODT_DISABLE")
	)
	(segment
		(start 327.891394 -38.524942)
		(end 327.723754 -38.120574)
		(width 0.12954)
		(layer "B.Cu")
		(net "FM_JTAG_ODT_DISABLE")
	)
	(segment
		(start 328.994008 -40.836596)
		(end 328.42327 -40.836596)
		(width 0.0889)
		(layer "B.Cu")
		(net "FM_JTAG_ODT_DISABLE")
	)
	(segment
		(start 326.712072 -37.108892)
		(end 326.712072 -36.66871)
		(width 0.12954)
		(layer "B.Cu")
		(net "FM_JTAG_ODT_DISABLE")
	)
	(segment
		(start 328.245216 -40.658542)
		(end 328.245216 -40.091868)
		(width 0.0889)
		(layer "B.Cu")
		(net "FM_JTAG_ODT_DISABLE")
	)
	(arc
		(start 329.440286 -40.557196)
		(mid 329.289521 -40.588782)
		(end 329.164188 -40.678354)
		(width 0.0889)
		(layer "B.Cu")
		(net "FM_JTAG_ODT_DISABLE")
	)
	(arc
		(start 329.764898 -40.744648)
		(mid 329.627927 -40.607597)
		(end 329.440794 -40.55745)
		(width 0.0889)
		(layer "B.Cu")
		(net "FM_JTAG_ODT_DISABLE")
	)
	(segment
		(start 186.647582 -126.342394)
		(end 186.647582 -124.743464)
		(width 0.12954)
		(layer "F.Cu")
		(net "FM_JTAG_BMC_MUX_SEL_R")
	)
	(segment
		(start 187.650374 -126.745238)
		(end 189.10554 -126.745238)
		(width 0.12954)
		(layer "F.Cu")
		(net "FM_JTAG_BMC_MUX_SEL_R")
	)
	(segment
		(start 184.932066 -123.027948)
		(end 184.208166 -123.027948)
		(width 0.12954)
		(layer "F.Cu")
		(net "FM_JTAG_BMC_MUX_SEL_R")
	)
	(segment
		(start 187.3504 -127.045212)
		(end 186.647582 -126.342394)
		(width 0.12954)
		(layer "F.Cu")
		(net "FM_JTAG_BMC_MUX_SEL_R")
	)
	(segment
		(start 189.10554 -126.745238)
		(end 189.28588 -126.564898)
		(width 0.12954)
		(layer "F.Cu")
		(net "FM_JTAG_BMC_MUX_SEL_R")
	)
	(segment
		(start 187.3504 -127.045212)
		(end 187.650374 -126.745238)
		(width 0.12954)
		(layer "F.Cu")
		(net "FM_JTAG_BMC_MUX_SEL_R")
	)
	(segment
		(start 186.647582 -124.743464)
		(end 184.932066 -123.027948)
		(width 0.12954)
		(layer "F.Cu")
		(net "FM_JTAG_BMC_MUX_SEL_R")
	)
	(segment
		(start 184.208166 -123.027948)
		(end 182.955692 -121.775474)
		(width 0.12954)
		(layer "F.Cu")
		(net "FM_JTAG_BMC_MUX_SEL_R")
	)
	(via
		(at 187.3504 -127.045212)
		(size 0.762)
		(drill 0.381)
		(layers "F.Cu" "B.Cu")
		(net "FM_JTAG_BMC_MUX_SEL_R")
	)
	(segment
		(start 125.072394 -77.571092)
		(end 125.072394 -78.587092)
		(width 0.12954)
		(layer "F.Cu")
		(net "FM_JTAG_BMC_MUX_SEL")
	)
	(segment
		(start 117.53088 -77.498956)
		(end 118.063772 -77.498956)
		(width 0.12954)
		(layer "F.Cu")
		(net "FM_JTAG_BMC_MUX_SEL")
	)
	(segment
		(start 117.280944 -77.748892)
		(end 117.53088 -77.498956)
		(width 0.12954)
		(layer "F.Cu")
		(net "FM_JTAG_BMC_MUX_SEL")
	)
	(segment
		(start 117.53088 -77.998828)
		(end 117.280944 -77.748892)
		(width 0.12954)
		(layer "F.Cu")
		(net "FM_JTAG_BMC_MUX_SEL")
	)
	(segment
		(start 118.063772 -77.998828)
		(end 117.53088 -77.998828)
		(width 0.12954)
		(layer "F.Cu")
		(net "FM_JTAG_BMC_MUX_SEL")
	)
	(segment
		(start 126.01448 -77.321156)
		(end 126.547372 -77.321156)
		(width 0.12954)
		(layer "F.Cu")
		(net "FM_JTAG_BMC_MUX_SEL")
	)
	(segment
		(start 126.01448 -77.821028)
		(end 125.764544 -77.571092)
		(width 0.12954)
		(layer "F.Cu")
		(net "FM_JTAG_BMC_MUX_SEL")
	)
	(segment
		(start 125.764544 -77.571092)
		(end 125.072394 -77.571092)
		(width 0.12954)
		(layer "F.Cu")
		(net "FM_JTAG_BMC_MUX_SEL")
	)
	(segment
		(start 126.547372 -77.821028)
		(end 126.01448 -77.821028)
		(width 0.12954)
		(layer "F.Cu")
		(net "FM_JTAG_BMC_MUX_SEL")
	)
	(segment
		(start 189.28588 -127.364998)
		(end 189.28588 -127.975868)
		(width 0.12954)
		(layer "F.Cu")
		(net "FM_JTAG_BMC_MUX_SEL")
	)
	(segment
		(start 125.764544 -77.571092)
		(end 126.01448 -77.321156)
		(width 0.12954)
		(layer "F.Cu")
		(net "FM_JTAG_BMC_MUX_SEL")
	)
	(via
		(at 150.13178 -128.2446)
		(size 0.508)
		(drill 0.254)
		(layers "F.Cu" "B.Cu")
		(net "FM_JTAG_BMC_MUX_SEL")
	)
	(via
		(at 120.407176 -127.94615)
		(size 0.508)
		(drill 0.254)
		(layers "F.Cu" "B.Cu")
		(net "FM_JTAG_BMC_MUX_SEL")
	)
	(via
		(at 125.764544 -77.571092)
		(size 0.508)
		(drill 0.254)
		(layers "F.Cu" "B.Cu")
		(net "FM_JTAG_BMC_MUX_SEL")
	)
	(via
		(at 117.280944 -77.748892)
		(size 0.508)
		(drill 0.254)
		(layers "F.Cu" "B.Cu")
		(net "FM_JTAG_BMC_MUX_SEL")
	)
	(via
		(at 148.5773 -13.929868)
		(size 0.508)
		(drill 0.254)
		(layers "F.Cu" "B.Cu")
		(net "FM_JTAG_BMC_MUX_SEL")
	)
	(via
		(at 189.28588 -127.975868)
		(size 0.508)
		(drill 0.254)
		(layers "F.Cu" "B.Cu")
		(net "FM_JTAG_BMC_MUX_SEL")
	)
	(via
		(at 113.284 -86.197948)
		(size 0.508)
		(drill 0.254)
		(layers "F.Cu" "B.Cu")
		(net "FM_JTAG_BMC_MUX_SEL")
	)
	(segment
		(start 148.5773 -13.929868)
		(end 148.02993 -13.382498)
		(width 0.12954)
		(layer "B.Cu")
		(net "FM_JTAG_BMC_MUX_SEL")
	)
	(segment
		(start 148.02993 -13.382498)
		(end 147.70608 -13.382498)
		(width 0.12954)
		(layer "B.Cu")
		(net "FM_JTAG_BMC_MUX_SEL")
	)
	(segment
		(start 113.284 -86.899242)
		(end 113.284 -86.197948)
		(width 0.127)
		(layer "In2.Cu")
		(net "FM_JTAG_BMC_MUX_SEL")
	)
	(segment
		(start 136.534398 -76.75499)
		(end 130.486912 -76.75499)
		(width 0.127)
		(layer "In2.Cu")
		(net "FM_JTAG_BMC_MUX_SEL")
	)
	(segment
		(start 148.5773 -13.929868)
		(end 148.190712 -13.929868)
		(width 0.127)
		(layer "In2.Cu")
		(net "FM_JTAG_BMC_MUX_SEL")
	)
	(segment
		(start 114.808 -87.509604)
		(end 113.894362 -87.509604)
		(width 0.127)
		(layer "In2.Cu")
		(net "FM_JTAG_BMC_MUX_SEL")
	)
	(segment
		(start 122.274076 -77.748892)
		(end 117.280944 -77.748892)
		(width 0.127)
		(layer "In2.Cu")
		(net "FM_JTAG_BMC_MUX_SEL")
	)
	(segment
		(start 120.407176 -127.94615)
		(end 120.407176 -124.111004)
		(width 0.127)
		(layer "In2.Cu")
		(net "FM_JTAG_BMC_MUX_SEL")
	)
	(segment
		(start 125.764544 -77.571092)
		(end 124.98578 -76.792328)
		(width 0.127)
		(layer "In2.Cu")
		(net "FM_JTAG_BMC_MUX_SEL")
	)
	(segment
		(start 120.407176 -124.111004)
		(end 121.15927 -123.35891)
		(width 0.127)
		(layer "In2.Cu")
		(net "FM_JTAG_BMC_MUX_SEL")
	)
	(segment
		(start 119.455184 -103.646224)
		(end 119.455184 -100.010722)
		(width 0.127)
		(layer "In2.Cu")
		(net "FM_JTAG_BMC_MUX_SEL")
	)
	(segment
		(start 116.529358 -97.084896)
		(end 116.529358 -89.230962)
		(width 0.127)
		(layer "In2.Cu")
		(net "FM_JTAG_BMC_MUX_SEL")
	)
	(segment
		(start 124.98578 -76.792328)
		(end 123.23064 -76.792328)
		(width 0.127)
		(layer "In2.Cu")
		(net "FM_JTAG_BMC_MUX_SEL")
	)
	(segment
		(start 129.67081 -77.571092)
		(end 125.764544 -77.571092)
		(width 0.127)
		(layer "In2.Cu")
		(net "FM_JTAG_BMC_MUX_SEL")
	)
	(segment
		(start 145.50136 -33.170368)
		(end 142.89786 -35.773868)
		(width 0.127)
		(layer "In2.Cu")
		(net "FM_JTAG_BMC_MUX_SEL")
	)
	(segment
		(start 119.455184 -100.010722)
		(end 116.529358 -97.084896)
		(width 0.127)
		(layer "In2.Cu")
		(net "FM_JTAG_BMC_MUX_SEL")
	)
	(segment
		(start 121.15927 -123.35891)
		(end 121.15927 -111.230156)
		(width 0.127)
		(layer "In2.Cu")
		(net "FM_JTAG_BMC_MUX_SEL")
	)
	(segment
		(start 142.89786 -59.202828)
		(end 138.938 -63.162688)
		(width 0.127)
		(layer "In2.Cu")
		(net "FM_JTAG_BMC_MUX_SEL")
	)
	(segment
		(start 120.392444 -110.46333)
		(end 120.392444 -104.583484)
		(width 0.127)
		(layer "In2.Cu")
		(net "FM_JTAG_BMC_MUX_SEL")
	)
	(segment
		(start 123.23064 -76.792328)
		(end 122.274076 -77.748892)
		(width 0.127)
		(layer "In2.Cu")
		(net "FM_JTAG_BMC_MUX_SEL")
	)
	(segment
		(start 120.392444 -104.583484)
		(end 119.455184 -103.646224)
		(width 0.127)
		(layer "In2.Cu")
		(net "FM_JTAG_BMC_MUX_SEL")
	)
	(segment
		(start 138.938 -74.351388)
		(end 136.534398 -76.75499)
		(width 0.127)
		(layer "In2.Cu")
		(net "FM_JTAG_BMC_MUX_SEL")
	)
	(segment
		(start 130.486912 -76.75499)
		(end 129.67081 -77.571092)
		(width 0.127)
		(layer "In2.Cu")
		(net "FM_JTAG_BMC_MUX_SEL")
	)
	(segment
		(start 145.50136 -16.61922)
		(end 145.50136 -33.170368)
		(width 0.127)
		(layer "In2.Cu")
		(net "FM_JTAG_BMC_MUX_SEL")
	)
	(segment
		(start 142.89786 -35.773868)
		(end 142.89786 -59.202828)
		(width 0.127)
		(layer "In2.Cu")
		(net "FM_JTAG_BMC_MUX_SEL")
	)
	(segment
		(start 138.938 -63.162688)
		(end 138.938 -74.351388)
		(width 0.127)
		(layer "In2.Cu")
		(net "FM_JTAG_BMC_MUX_SEL")
	)
	(segment
		(start 113.894362 -87.509604)
		(end 113.284 -86.899242)
		(width 0.127)
		(layer "In2.Cu")
		(net "FM_JTAG_BMC_MUX_SEL")
	)
	(segment
		(start 148.190712 -13.929868)
		(end 145.50136 -16.61922)
		(width 0.127)
		(layer "In2.Cu")
		(net "FM_JTAG_BMC_MUX_SEL")
	)
	(segment
		(start 116.529358 -89.230962)
		(end 114.808 -87.509604)
		(width 0.127)
		(layer "In2.Cu")
		(net "FM_JTAG_BMC_MUX_SEL")
	)
	(segment
		(start 121.15927 -111.230156)
		(end 120.392444 -110.46333)
		(width 0.127)
		(layer "In2.Cu")
		(net "FM_JTAG_BMC_MUX_SEL")
	)
	(segment
		(start 158.46806 -129.806446)
		(end 156.778198 -128.116584)
		(width 0.127)
		(layer "In6.Cu")
		(net "FM_JTAG_BMC_MUX_SEL")
	)
	(segment
		(start 188.621162 -127.975868)
		(end 187.994798 -127.349504)
		(width 0.127)
		(layer "In6.Cu")
		(net "FM_JTAG_BMC_MUX_SEL")
	)
	(segment
		(start 150.86711 -126.81331)
		(end 150.13178 -127.54864)
		(width 0.127)
		(layer "In6.Cu")
		(net "FM_JTAG_BMC_MUX_SEL")
	)
	(segment
		(start 150.13178 -127.54864)
		(end 150.13178 -128.2446)
		(width 0.127)
		(layer "In6.Cu")
		(net "FM_JTAG_BMC_MUX_SEL")
	)
	(segment
		(start 165.801294 -129.806446)
		(end 158.46806 -129.806446)
		(width 0.127)
		(layer "In6.Cu")
		(net "FM_JTAG_BMC_MUX_SEL")
	)
	(segment
		(start 156.778198 -127.80391)
		(end 155.787598 -126.81331)
		(width 0.127)
		(layer "In6.Cu")
		(net "FM_JTAG_BMC_MUX_SEL")
	)
	(segment
		(start 156.778198 -128.116584)
		(end 156.778198 -127.80391)
		(width 0.127)
		(layer "In6.Cu")
		(net "FM_JTAG_BMC_MUX_SEL")
	)
	(segment
		(start 169.977816 -127.349504)
		(end 169.49166 -127.83566)
		(width 0.127)
		(layer "In6.Cu")
		(net "FM_JTAG_BMC_MUX_SEL")
	)
	(segment
		(start 167.77208 -127.83566)
		(end 165.801294 -129.806446)
		(width 0.127)
		(layer "In6.Cu")
		(net "FM_JTAG_BMC_MUX_SEL")
	)
	(segment
		(start 169.49166 -127.83566)
		(end 167.77208 -127.83566)
		(width 0.127)
		(layer "In6.Cu")
		(net "FM_JTAG_BMC_MUX_SEL")
	)
	(segment
		(start 155.787598 -126.81331)
		(end 150.86711 -126.81331)
		(width 0.127)
		(layer "In6.Cu")
		(net "FM_JTAG_BMC_MUX_SEL")
	)
	(segment
		(start 187.994798 -127.349504)
		(end 169.977816 -127.349504)
		(width 0.127)
		(layer "In6.Cu")
		(net "FM_JTAG_BMC_MUX_SEL")
	)
	(segment
		(start 189.28588 -127.975868)
		(end 188.621162 -127.975868)
		(width 0.127)
		(layer "In6.Cu")
		(net "FM_JTAG_BMC_MUX_SEL")
	)
	(segment
		(start 113.674906 -83.678268)
		(end 113.674906 -85.807042)
		(width 0.127)
		(layer "In11.Cu")
		(net "FM_JTAG_BMC_MUX_SEL")
	)
	(segment
		(start 117.280944 -77.748892)
		(end 115.989862 -79.039974)
		(width 0.127)
		(layer "In11.Cu")
		(net "FM_JTAG_BMC_MUX_SEL")
	)
	(segment
		(start 115.989862 -81.363312)
		(end 113.674906 -83.678268)
		(width 0.127)
		(layer "In11.Cu")
		(net "FM_JTAG_BMC_MUX_SEL")
	)
	(segment
		(start 113.674906 -85.807042)
		(end 113.284 -86.197948)
		(width 0.127)
		(layer "In11.Cu")
		(net "FM_JTAG_BMC_MUX_SEL")
	)
	(segment
		(start 115.989862 -79.039974)
		(end 115.989862 -81.363312)
		(width 0.127)
		(layer "In11.Cu")
		(net "FM_JTAG_BMC_MUX_SEL")
	)
	(segment
		(start 134.044436 -127.94615)
		(end 120.407176 -127.94615)
		(width 0.127)
		(layer "In13.Cu")
		(net "FM_JTAG_BMC_MUX_SEL")
	)
	(segment
		(start 134.469632 -128.371346)
		(end 134.044436 -127.94615)
		(width 0.127)
		(layer "In13.Cu")
		(net "FM_JTAG_BMC_MUX_SEL")
	)
	(segment
		(start 150.13178 -128.2446)
		(end 147.973288 -128.2446)
		(width 0.127)
		(layer "In13.Cu")
		(net "FM_JTAG_BMC_MUX_SEL")
	)
	(segment
		(start 134.469632 -128.58496)
		(end 134.469632 -128.371346)
		(width 0.127)
		(layer "In13.Cu")
		(net "FM_JTAG_BMC_MUX_SEL")
	)
	(segment
		(start 135.379206 -129.494534)
		(end 134.469632 -128.58496)
		(width 0.127)
		(layer "In13.Cu")
		(net "FM_JTAG_BMC_MUX_SEL")
	)
	(segment
		(start 146.723354 -129.494534)
		(end 135.379206 -129.494534)
		(width 0.127)
		(layer "In13.Cu")
		(net "FM_JTAG_BMC_MUX_SEL")
	)
	(segment
		(start 147.973288 -128.2446)
		(end 146.723354 -129.494534)
		(width 0.127)
		(layer "In13.Cu")
		(net "FM_JTAG_BMC_MUX_SEL")
	)
	(segment
		(start 329.429364 -34.74339)
		(end 328.349864 -33.66389)
		(width 0.0889)
		(layer "F.Cu")
		(net "FM_INTRUDER_HDR_PCH_N")
	)
	(segment
		(start 329.429364 -35.998404)
		(end 329.429364 -34.74339)
		(width 0.0889)
		(layer "F.Cu")
		(net "FM_INTRUDER_HDR_PCH_N")
	)
	(segment
		(start 325.31558 -29.513022)
		(end 326.3265 -31.025592)
		(width 0.12954)
		(layer "F.Cu")
		(net "FM_INTRUDER_HDR_PCH_N")
	)
	(segment
		(start 330.025756 -37.256974)
		(end 330.025756 -36.594796)
		(width 0.0889)
		(layer "F.Cu")
		(net "FM_INTRUDER_HDR_PCH_N")
	)
	(segment
		(start 330.025756 -36.594796)
		(end 329.429364 -35.998404)
		(width 0.0889)
		(layer "F.Cu")
		(net "FM_INTRUDER_HDR_PCH_N")
	)
	(segment
		(start 326.3265 -31.025592)
		(end 326.904096 -31.603188)
		(width 0.12954)
		(layer "F.Cu")
		(net "FM_INTRUDER_HDR_PCH_N")
	)
	(segment
		(start 327.543922 -32.362648)
		(end 327.175622 -31.994348)
		(width 0.12954)
		(layer "F.Cu")
		(net "FM_INTRUDER_HDR_PCH_N")
	)
	(segment
		(start 327.543922 -32.856678)
		(end 327.543922 -32.362648)
		(width 0.12954)
		(layer "F.Cu")
		(net "FM_INTRUDER_HDR_PCH_N")
	)
	(segment
		(start 326.904096 -31.722822)
		(end 327.175622 -31.994348)
		(width 0.12954)
		(layer "F.Cu")
		(net "FM_INTRUDER_HDR_PCH_N")
	)
	(segment
		(start 326.904096 -31.603188)
		(end 326.904096 -31.722822)
		(width 0.12954)
		(layer "F.Cu")
		(net "FM_INTRUDER_HDR_PCH_N")
	)
	(segment
		(start 323.815456 -28.012898)
		(end 325.31558 -29.513022)
		(width 0.12954)
		(layer "F.Cu")
		(net "FM_INTRUDER_HDR_PCH_N")
	)
	(segment
		(start 329.89647 -37.63518)
		(end 329.89647 -37.38626)
		(width 0.0889)
		(layer "F.Cu")
		(net "FM_INTRUDER_HDR_PCH_N")
	)
	(segment
		(start 329.89647 -37.38626)
		(end 330.025756 -37.256974)
		(width 0.0889)
		(layer "F.Cu")
		(net "FM_INTRUDER_HDR_PCH_N")
	)
	(segment
		(start 328.349864 -33.66389)
		(end 327.543922 -32.856678)
		(width 0.12954)
		(layer "F.Cu")
		(net "FM_INTRUDER_HDR_PCH_N")
	)
	(via
		(at 327.175622 -31.994348)
		(size 0.508)
		(drill 0.254)
		(layers "F.Cu" "B.Cu")
		(net "FM_INTRUDER_HDR_PCH_N")
	)
	(segment
		(start 117.154706 -359.389172)
		(end 117.154706 -360.844846)
		(width 0.12954)
		(layer "F.Cu")
		(net "FM_HBM_VPP_SEL_CPU1_D")
	)
	(segment
		(start 119.02948 -357.514398)
		(end 117.154706 -359.389172)
		(width 0.12954)
		(layer "F.Cu")
		(net "FM_HBM_VPP_SEL_CPU1_D")
	)
	(segment
		(start 117.711728 -361.401868)
		(end 117.154706 -360.844846)
		(width 0.12954)
		(layer "F.Cu")
		(net "FM_HBM_VPP_SEL_CPU1_D")
	)
	(segment
		(start 118.6561 -361.401868)
		(end 117.711728 -361.401868)
		(width 0.12954)
		(layer "F.Cu")
		(net "FM_HBM_VPP_SEL_CPU1_D")
	)
	(via
		(at 117.154706 -360.844846)
		(size 0.762)
		(drill 0.381)
		(layers "F.Cu" "B.Cu")
		(net "FM_HBM_VPP_SEL_CPU1_D")
	)
	(segment
		(start 365.167164 -361.144312)
		(end 365.167164 -358.927908)
		(width 0.12954)
		(layer "F.Cu")
		(net "FM_HBM_VPP_SEL_CPU0_D")
	)
	(segment
		(start 366.580674 -357.514398)
		(end 366.95888 -357.514398)
		(width 0.12954)
		(layer "F.Cu")
		(net "FM_HBM_VPP_SEL_CPU0_D")
	)
	(segment
		(start 365.167164 -358.927908)
		(end 366.580674 -357.514398)
		(width 0.12954)
		(layer "F.Cu")
		(net "FM_HBM_VPP_SEL_CPU0_D")
	)
	(segment
		(start 365.7092 -361.686348)
		(end 365.167164 -361.144312)
		(width 0.12954)
		(layer "F.Cu")
		(net "FM_HBM_VPP_SEL_CPU0_D")
	)
	(segment
		(start 366.644428 -361.686348)
		(end 365.7092 -361.686348)
		(width 0.12954)
		(layer "F.Cu")
		(net "FM_HBM_VPP_SEL_CPU0_D")
	)
	(via
		(at 365.167164 -361.144312)
		(size 0.762)
		(drill 0.381)
		(layers "F.Cu" "B.Cu")
		(net "FM_HBM_VPP_SEL_CPU0_D")
	)
	(segment
		(start 367.594388 -363.886496)
		(end 366.693704 -363.886496)
		(width 0.12954)
		(layer "F.Cu")
		(net "FM_HBM2_HBM3_VPP_SEL")
	)
	(segment
		(start 119.60606 -363.602016)
		(end 119.60606 -364.702852)
		(width 0.12954)
		(layer "F.Cu")
		(net "FM_HBM2_HBM3_VPP_SEL")
	)
	(segment
		(start 185.355738 -108.975398)
		(end 185.755788 -108.575348)
		(width 0.12954)
		(layer "F.Cu")
		(net "FM_HBM2_HBM3_VPP_SEL")
	)
	(via
		(at 233.27868 -204.231748)
		(size 0.508)
		(drill 0.254)
		(layers "F.Cu" "B.Cu")
		(net "FM_HBM2_HBM3_VPP_SEL")
	)
	(via
		(at 301.68088 -385.492752)
		(size 0.508)
		(drill 0.254)
		(layers "F.Cu" "B.Cu")
		(net "FM_HBM2_HBM3_VPP_SEL")
	)
	(via
		(at 366.693704 -363.886496)
		(size 0.508)
		(drill 0.254)
		(layers "F.Cu" "B.Cu")
		(net "FM_HBM2_HBM3_VPP_SEL")
	)
	(via
		(at 119.60606 -364.702852)
		(size 0.508)
		(drill 0.254)
		(layers "F.Cu" "B.Cu")
		(net "FM_HBM2_HBM3_VPP_SEL")
	)
	(via
		(at 118.59387 -398.233138)
		(size 0.508)
		(drill 0.254)
		(layers "F.Cu" "B.Cu")
		(net "FM_HBM2_HBM3_VPP_SEL")
	)
	(via
		(at 347.26118 -369.098068)
		(size 0.508)
		(drill 0.254)
		(layers "F.Cu" "B.Cu")
		(net "FM_HBM2_HBM3_VPP_SEL")
	)
	(via
		(at 185.755788 -108.575348)
		(size 0.4572)
		(drill 0.254)
		(layers "F.Cu" "B.Cu")
		(net "FM_HBM2_HBM3_VPP_SEL")
	)
	(via
		(at 172.36694 -401.867116)
		(size 0.508)
		(drill 0.254)
		(layers "F.Cu" "B.Cu")
		(net "FM_HBM2_HBM3_VPP_SEL")
	)
	(segment
		(start 199.73036 -370.7892)
		(end 199.73036 -363.1438)
		(width 0.127)
		(layer "In4.Cu")
		(net "FM_HBM2_HBM3_VPP_SEL")
	)
	(segment
		(start 119.60606 -364.702852)
		(end 119.60606 -385.430268)
		(width 0.127)
		(layer "In4.Cu")
		(net "FM_HBM2_HBM3_VPP_SEL")
	)
	(segment
		(start 119.657368 -394.383768)
		(end 120.1166 -394.843)
		(width 0.127)
		(layer "In4.Cu")
		(net "FM_HBM2_HBM3_VPP_SEL")
	)
	(segment
		(start 120.1166 -394.843)
		(end 120.1166 -396.235428)
		(width 0.127)
		(layer "In4.Cu")
		(net "FM_HBM2_HBM3_VPP_SEL")
	)
	(segment
		(start 118.59387 -397.758158)
		(end 118.59387 -398.233138)
		(width 0.127)
		(layer "In4.Cu")
		(net "FM_HBM2_HBM3_VPP_SEL")
	)
	(segment
		(start 190.60414 -379.91542)
		(end 199.73036 -370.7892)
		(width 0.127)
		(layer "In4.Cu")
		(net "FM_HBM2_HBM3_VPP_SEL")
	)
	(segment
		(start 362.617766 -370.43995)
		(end 352.888042 -370.43995)
		(width 0.127)
		(layer "In4.Cu")
		(net "FM_HBM2_HBM3_VPP_SEL")
	)
	(segment
		(start 120.1166 -396.235428)
		(end 118.59387 -397.758158)
		(width 0.127)
		(layer "In4.Cu")
		(net "FM_HBM2_HBM3_VPP_SEL")
	)
	(segment
		(start 176.181004 -395.059916)
		(end 176.181004 -388.054596)
		(width 0.127)
		(layer "In4.Cu")
		(net "FM_HBM2_HBM3_VPP_SEL")
	)
	(segment
		(start 176.181004 -388.054596)
		(end 184.32018 -379.91542)
		(width 0.127)
		(layer "In4.Cu")
		(net "FM_HBM2_HBM3_VPP_SEL")
	)
	(segment
		(start 119.60606 -385.430268)
		(end 114.65052 -390.385808)
		(width 0.127)
		(layer "In4.Cu")
		(net "FM_HBM2_HBM3_VPP_SEL")
	)
	(segment
		(start 184.32018 -379.91542)
		(end 190.60414 -379.91542)
		(width 0.127)
		(layer "In4.Cu")
		(net "FM_HBM2_HBM3_VPP_SEL")
	)
	(segment
		(start 366.693704 -366.364012)
		(end 362.617766 -370.43995)
		(width 0.127)
		(layer "In4.Cu")
		(net "FM_HBM2_HBM3_VPP_SEL")
	)
	(segment
		(start 172.9994 -401.522184)
		(end 172.9994 -398.24152)
		(width 0.127)
		(layer "In4.Cu")
		(net "FM_HBM2_HBM3_VPP_SEL")
	)
	(segment
		(start 212.541612 -350.332548)
		(end 216.48928 -350.332548)
		(width 0.127)
		(layer "In4.Cu")
		(net "FM_HBM2_HBM3_VPP_SEL")
	)
	(segment
		(start 231.11968 -241.468148)
		(end 231.11968 -206.390748)
		(width 0.127)
		(layer "In4.Cu")
		(net "FM_HBM2_HBM3_VPP_SEL")
	)
	(segment
		(start 172.36694 -401.867116)
		(end 172.654468 -401.867116)
		(width 0.127)
		(layer "In4.Cu")
		(net "FM_HBM2_HBM3_VPP_SEL")
	)
	(segment
		(start 351.54616 -369.098068)
		(end 347.26118 -369.098068)
		(width 0.127)
		(layer "In4.Cu")
		(net "FM_HBM2_HBM3_VPP_SEL")
	)
	(segment
		(start 117.213888 -394.383768)
		(end 119.657368 -394.383768)
		(width 0.127)
		(layer "In4.Cu")
		(net "FM_HBM2_HBM3_VPP_SEL")
	)
	(segment
		(start 223.90608 -248.681748)
		(end 231.11968 -241.468148)
		(width 0.127)
		(layer "In4.Cu")
		(net "FM_HBM2_HBM3_VPP_SEL")
	)
	(segment
		(start 114.65052 -391.8204)
		(end 117.213888 -394.383768)
		(width 0.127)
		(layer "In4.Cu")
		(net "FM_HBM2_HBM3_VPP_SEL")
	)
	(segment
		(start 366.693704 -363.886496)
		(end 366.693704 -366.364012)
		(width 0.127)
		(layer "In4.Cu")
		(net "FM_HBM2_HBM3_VPP_SEL")
	)
	(segment
		(start 216.48928 -350.332548)
		(end 223.90608 -342.915748)
		(width 0.127)
		(layer "In4.Cu")
		(net "FM_HBM2_HBM3_VPP_SEL")
	)
	(segment
		(start 231.11968 -206.390748)
		(end 233.27868 -204.231748)
		(width 0.127)
		(layer "In4.Cu")
		(net "FM_HBM2_HBM3_VPP_SEL")
	)
	(segment
		(start 223.90608 -342.915748)
		(end 223.90608 -248.681748)
		(width 0.127)
		(layer "In4.Cu")
		(net "FM_HBM2_HBM3_VPP_SEL")
	)
	(segment
		(start 352.888042 -370.43995)
		(end 351.54616 -369.098068)
		(width 0.127)
		(layer "In4.Cu")
		(net "FM_HBM2_HBM3_VPP_SEL")
	)
	(segment
		(start 199.73036 -363.1438)
		(end 212.541612 -350.332548)
		(width 0.127)
		(layer "In4.Cu")
		(net "FM_HBM2_HBM3_VPP_SEL")
	)
	(segment
		(start 172.9994 -398.24152)
		(end 176.181004 -395.059916)
		(width 0.127)
		(layer "In4.Cu")
		(net "FM_HBM2_HBM3_VPP_SEL")
	)
	(segment
		(start 114.65052 -390.385808)
		(end 114.65052 -391.8204)
		(width 0.127)
		(layer "In4.Cu")
		(net "FM_HBM2_HBM3_VPP_SEL")
	)
	(segment
		(start 172.654468 -401.867116)
		(end 172.9994 -401.522184)
		(width 0.127)
		(layer "In4.Cu")
		(net "FM_HBM2_HBM3_VPP_SEL")
	)
	(segment
		(start 346.435426 -369.098068)
		(end 342.98255 -372.550944)
		(width 0.127)
		(layer "In6.Cu")
		(net "FM_HBM2_HBM3_VPP_SEL")
	)
	(segment
		(start 342.98255 -372.550944)
		(end 330.272644 -372.550944)
		(width 0.127)
		(layer "In6.Cu")
		(net "FM_HBM2_HBM3_VPP_SEL")
	)
	(segment
		(start 330.272644 -372.550944)
		(end 317.330836 -385.492752)
		(width 0.127)
		(layer "In6.Cu")
		(net "FM_HBM2_HBM3_VPP_SEL")
	)
	(segment
		(start 317.330836 -385.492752)
		(end 301.68088 -385.492752)
		(width 0.127)
		(layer "In6.Cu")
		(net "FM_HBM2_HBM3_VPP_SEL")
	)
	(segment
		(start 347.26118 -369.098068)
		(end 346.435426 -369.098068)
		(width 0.127)
		(layer "In6.Cu")
		(net "FM_HBM2_HBM3_VPP_SEL")
	)
	(segment
		(start 272.261838 -437.85028)
		(end 275.59127 -434.520848)
		(width 0.127)
		(layer "In11.Cu")
		(net "FM_HBM2_HBM3_VPP_SEL")
	)
	(segment
		(start 175.67656 -418.04082)
		(end 177.70094 -420.0652)
		(width 0.127)
		(layer "In11.Cu")
		(net "FM_HBM2_HBM3_VPP_SEL")
	)
	(segment
		(start 173.24578 -402.745956)
		(end 173.24578 -408.27198)
		(width 0.127)
		(layer "In11.Cu")
		(net "FM_HBM2_HBM3_VPP_SEL")
	)
	(segment
		(start 173.02226 -418.04082)
		(end 175.67656 -418.04082)
		(width 0.127)
		(layer "In11.Cu")
		(net "FM_HBM2_HBM3_VPP_SEL")
	)
	(segment
		(start 186.744864 -150.411688)
		(end 184.646824 -152.509728)
		(width 0.127)
		(layer "In11.Cu")
		(net "FM_HBM2_HBM3_VPP_SEL")
	)
	(segment
		(start 294.8686 -409.53944)
		(end 294.8686 -406.6286)
		(width 0.127)
		(layer "In11.Cu")
		(net "FM_HBM2_HBM3_VPP_SEL")
	)
	(segment
		(start 186.23026 -187.640468)
		(end 186.63666 -188.046868)
		(width 0.127)
		(layer "In11.Cu")
		(net "FM_HBM2_HBM3_VPP_SEL")
	)
	(segment
		(start 295.71188 -427.101)
		(end 295.71188 -422.29024)
		(width 0.127)
		(layer "In11.Cu")
		(net "FM_HBM2_HBM3_VPP_SEL")
	)
	(segment
		(start 187.8076 -135.832088)
		(end 187.8076 -143.721328)
		(width 0.127)
		(layer "In11.Cu")
		(net "FM_HBM2_HBM3_VPP_SEL")
	)
	(segment
		(start 207.835246 -190.657988)
		(end 207.946752 -190.546482)
		(width 0.127)
		(layer "In11.Cu")
		(net "FM_HBM2_HBM3_VPP_SEL")
	)
	(segment
		(start 300.26356 -386.910072)
		(end 301.68088 -385.492752)
		(width 0.127)
		(layer "In11.Cu")
		(net "FM_HBM2_HBM3_VPP_SEL")
	)
	(segment
		(start 297.528742 -405.74595)
		(end 299.116242 -404.15845)
		(width 0.127)
		(layer "In11.Cu")
		(net "FM_HBM2_HBM3_VPP_SEL")
	)
	(segment
		(start 187.30468 -108.575348)
		(end 189.93612 -111.206788)
		(width 0.127)
		(layer "In11.Cu")
		(net "FM_HBM2_HBM3_VPP_SEL")
	)
	(segment
		(start 187.8076 -143.721328)
		(end 186.744864 -144.784064)
		(width 0.127)
		(layer "In11.Cu")
		(net "FM_HBM2_HBM3_VPP_SEL")
	)
	(segment
		(start 181.13121 -421.15105)
		(end 190.72352 -421.15105)
		(width 0.127)
		(layer "In11.Cu")
		(net "FM_HBM2_HBM3_VPP_SEL")
	)
	(segment
		(start 184.646824 -160.265872)
		(end 186.23026 -161.849308)
		(width 0.127)
		(layer "In11.Cu")
		(net "FM_HBM2_HBM3_VPP_SEL")
	)
	(segment
		(start 295.75125 -405.74595)
		(end 297.528742 -405.74595)
		(width 0.127)
		(layer "In11.Cu")
		(net "FM_HBM2_HBM3_VPP_SEL")
	)
	(segment
		(start 188.24448 -135.395208)
		(end 187.8076 -135.832088)
		(width 0.127)
		(layer "In11.Cu")
		(net "FM_HBM2_HBM3_VPP_SEL")
	)
	(segment
		(start 184.646824 -152.509728)
		(end 184.646824 -160.265872)
		(width 0.127)
		(layer "In11.Cu")
		(net "FM_HBM2_HBM3_VPP_SEL")
	)
	(segment
		(start 189.93612 -115.153948)
		(end 189.05728 -116.032788)
		(width 0.127)
		(layer "In11.Cu")
		(net "FM_HBM2_HBM3_VPP_SEL")
	)
	(segment
		(start 189.93612 -111.206788)
		(end 189.93612 -115.153948)
		(width 0.127)
		(layer "In11.Cu")
		(net "FM_HBM2_HBM3_VPP_SEL")
	)
	(segment
		(start 118.59387 -398.233138)
		(end 119.66448 -399.303748)
		(width 0.127)
		(layer "In11.Cu")
		(net "FM_HBM2_HBM3_VPP_SEL")
	)
	(segment
		(start 189.05728 -116.032788)
		(end 189.05728 -126.050548)
		(width 0.127)
		(layer "In11.Cu")
		(net "FM_HBM2_HBM3_VPP_SEL")
	)
	(segment
		(start 294.8686 -406.6286)
		(end 295.75125 -405.74595)
		(width 0.127)
		(layer "In11.Cu")
		(net "FM_HBM2_HBM3_VPP_SEL")
	)
	(segment
		(start 170.82262 -415.84118)
		(end 173.02226 -418.04082)
		(width 0.127)
		(layer "In11.Cu")
		(net "FM_HBM2_HBM3_VPP_SEL")
	)
	(segment
		(start 191.95288 -422.38041)
		(end 191.95288 -426.212)
		(width 0.127)
		(layer "In11.Cu")
		(net "FM_HBM2_HBM3_VPP_SEL")
	)
	(segment
		(start 232.782364 -204.728064)
		(end 233.27868 -204.231748)
		(width 0.127)
		(layer "In11.Cu")
		(net "FM_HBM2_HBM3_VPP_SEL")
	)
	(segment
		(start 295.15308 -427.6598)
		(end 295.71188 -427.101)
		(width 0.127)
		(layer "In11.Cu")
		(net "FM_HBM2_HBM3_VPP_SEL")
	)
	(segment
		(start 169.803572 -399.303748)
		(end 172.36694 -401.867116)
		(width 0.127)
		(layer "In11.Cu")
		(net "FM_HBM2_HBM3_VPP_SEL")
	)
	(segment
		(start 275.59127 -430.893728)
		(end 278.825198 -427.6598)
		(width 0.127)
		(layer "In11.Cu")
		(net "FM_HBM2_HBM3_VPP_SEL")
	)
	(segment
		(start 191.38392 -430.268634)
		(end 198.965566 -437.85028)
		(width 0.127)
		(layer "In11.Cu")
		(net "FM_HBM2_HBM3_VPP_SEL")
	)
	(segment
		(start 189.05728 -126.050548)
		(end 187.56376 -127.544068)
		(width 0.127)
		(layer "In11.Cu")
		(net "FM_HBM2_HBM3_VPP_SEL")
	)
	(segment
		(start 215.082374 -190.546482)
		(end 229.263956 -204.728064)
		(width 0.127)
		(layer "In11.Cu")
		(net "FM_HBM2_HBM3_VPP_SEL")
	)
	(segment
		(start 275.59127 -434.520848)
		(end 275.59127 -430.893728)
		(width 0.127)
		(layer "In11.Cu")
		(net "FM_HBM2_HBM3_VPP_SEL")
	)
	(segment
		(start 207.946752 -190.546482)
		(end 215.082374 -190.546482)
		(width 0.127)
		(layer "In11.Cu")
		(net "FM_HBM2_HBM3_VPP_SEL")
	)
	(segment
		(start 180.04536 -420.0652)
		(end 181.13121 -421.15105)
		(width 0.127)
		(layer "In11.Cu")
		(net "FM_HBM2_HBM3_VPP_SEL")
	)
	(segment
		(start 173.24578 -408.27198)
		(end 170.82262 -410.69514)
		(width 0.127)
		(layer "In11.Cu")
		(net "FM_HBM2_HBM3_VPP_SEL")
	)
	(segment
		(start 198.965566 -437.85028)
		(end 272.261838 -437.85028)
		(width 0.127)
		(layer "In11.Cu")
		(net "FM_HBM2_HBM3_VPP_SEL")
	)
	(segment
		(start 177.70094 -420.0652)
		(end 180.04536 -420.0652)
		(width 0.127)
		(layer "In11.Cu")
		(net "FM_HBM2_HBM3_VPP_SEL")
	)
	(segment
		(start 299.116242 -404.15845)
		(end 299.116242 -391.723118)
		(width 0.127)
		(layer "In11.Cu")
		(net "FM_HBM2_HBM3_VPP_SEL")
	)
	(segment
		(start 190.72352 -421.15105)
		(end 191.95288 -422.38041)
		(width 0.127)
		(layer "In11.Cu")
		(net "FM_HBM2_HBM3_VPP_SEL")
	)
	(segment
		(start 188.24448 -133.914388)
		(end 188.24448 -135.395208)
		(width 0.127)
		(layer "In11.Cu")
		(net "FM_HBM2_HBM3_VPP_SEL")
	)
	(segment
		(start 194.64274 -190.350648)
		(end 194.95008 -190.657988)
		(width 0.127)
		(layer "In11.Cu")
		(net "FM_HBM2_HBM3_VPP_SEL")
	)
	(segment
		(start 191.95288 -426.212)
		(end 191.38392 -426.78096)
		(width 0.127)
		(layer "In11.Cu")
		(net "FM_HBM2_HBM3_VPP_SEL")
	)
	(segment
		(start 295.71188 -422.29024)
		(end 293.54272 -420.12108)
		(width 0.127)
		(layer "In11.Cu")
		(net "FM_HBM2_HBM3_VPP_SEL")
	)
	(segment
		(start 170.82262 -410.69514)
		(end 170.82262 -415.84118)
		(width 0.127)
		(layer "In11.Cu")
		(net "FM_HBM2_HBM3_VPP_SEL")
	)
	(segment
		(start 300.26356 -390.5758)
		(end 300.26356 -386.910072)
		(width 0.127)
		(layer "In11.Cu")
		(net "FM_HBM2_HBM3_VPP_SEL")
	)
	(segment
		(start 293.54272 -410.86532)
		(end 294.8686 -409.53944)
		(width 0.127)
		(layer "In11.Cu")
		(net "FM_HBM2_HBM3_VPP_SEL")
	)
	(segment
		(start 278.825198 -427.6598)
		(end 295.15308 -427.6598)
		(width 0.127)
		(layer "In11.Cu")
		(net "FM_HBM2_HBM3_VPP_SEL")
	)
	(segment
		(start 185.755788 -108.575348)
		(end 187.30468 -108.575348)
		(width 0.127)
		(layer "In11.Cu")
		(net "FM_HBM2_HBM3_VPP_SEL")
	)
	(segment
		(start 229.263956 -204.728064)
		(end 232.782364 -204.728064)
		(width 0.127)
		(layer "In11.Cu")
		(net "FM_HBM2_HBM3_VPP_SEL")
	)
	(segment
		(start 186.63666 -189.614048)
		(end 187.37326 -190.350648)
		(width 0.127)
		(layer "In11.Cu")
		(net "FM_HBM2_HBM3_VPP_SEL")
	)
	(segment
		(start 187.56376 -127.544068)
		(end 187.56376 -133.233668)
		(width 0.127)
		(layer "In11.Cu")
		(net "FM_HBM2_HBM3_VPP_SEL")
	)
	(segment
		(start 186.744864 -144.784064)
		(end 186.744864 -150.411688)
		(width 0.127)
		(layer "In11.Cu")
		(net "FM_HBM2_HBM3_VPP_SEL")
	)
	(segment
		(start 293.54272 -420.12108)
		(end 293.54272 -410.86532)
		(width 0.127)
		(layer "In11.Cu")
		(net "FM_HBM2_HBM3_VPP_SEL")
	)
	(segment
		(start 191.38392 -426.78096)
		(end 191.38392 -430.268634)
		(width 0.127)
		(layer "In11.Cu")
		(net "FM_HBM2_HBM3_VPP_SEL")
	)
	(segment
		(start 299.116242 -391.723118)
		(end 300.26356 -390.5758)
		(width 0.127)
		(layer "In11.Cu")
		(net "FM_HBM2_HBM3_VPP_SEL")
	)
	(segment
		(start 186.63666 -188.046868)
		(end 186.63666 -189.614048)
		(width 0.127)
		(layer "In11.Cu")
		(net "FM_HBM2_HBM3_VPP_SEL")
	)
	(segment
		(start 194.95008 -190.657988)
		(end 207.835246 -190.657988)
		(width 0.127)
		(layer "In11.Cu")
		(net "FM_HBM2_HBM3_VPP_SEL")
	)
	(segment
		(start 187.37326 -190.350648)
		(end 194.64274 -190.350648)
		(width 0.127)
		(layer "In11.Cu")
		(net "FM_HBM2_HBM3_VPP_SEL")
	)
	(segment
		(start 186.23026 -161.849308)
		(end 186.23026 -187.640468)
		(width 0.127)
		(layer "In11.Cu")
		(net "FM_HBM2_HBM3_VPP_SEL")
	)
	(segment
		(start 187.56376 -133.233668)
		(end 188.24448 -133.914388)
		(width 0.127)
		(layer "In11.Cu")
		(net "FM_HBM2_HBM3_VPP_SEL")
	)
	(segment
		(start 172.36694 -401.867116)
		(end 173.24578 -402.745956)
		(width 0.127)
		(layer "In11.Cu")
		(net "FM_HBM2_HBM3_VPP_SEL")
	)
	(segment
		(start 119.66448 -399.303748)
		(end 169.803572 -399.303748)
		(width 0.127)
		(layer "In11.Cu")
		(net "FM_HBM2_HBM3_VPP_SEL")
	)
	(segment
		(start 182.955692 -112.175544)
		(end 183.355742 -111.775494)
		(width 0.12954)
		(layer "F.Cu")
		(net "FM_FORCE_PWRON_LVC3")
	)
	(via
		(at 183.355742 -111.775494)
		(size 0.4572)
		(drill 0.254)
		(layers "F.Cu" "B.Cu")
		(net "FM_FORCE_PWRON_LVC3")
	)
	(via
		(at 180.57876 -150.157688)
		(size 0.508)
		(drill 0.254)
		(layers "F.Cu" "B.Cu")
		(net "FM_FORCE_PWRON_LVC3")
	)
	(segment
		(start 180.57876 -150.157688)
		(end 180.57876 -141.409928)
		(width 0.127)
		(layer "In11.Cu")
		(net "FM_FORCE_PWRON_LVC3")
	)
	(segment
		(start 183.76138 -112.181132)
		(end 183.355742 -111.775494)
		(width 0.127)
		(layer "In11.Cu")
		(net "FM_FORCE_PWRON_LVC3")
	)
	(segment
		(start 184.3659 -120.172988)
		(end 183.95188 -120.172988)
		(width 0.127)
		(layer "In11.Cu")
		(net "FM_FORCE_PWRON_LVC3")
	)
	(segment
		(start 184.55386 -121.542048)
		(end 184.55386 -120.360948)
		(width 0.127)
		(layer "In11.Cu")
		(net "FM_FORCE_PWRON_LVC3")
	)
	(segment
		(start 183.09844 -138.890248)
		(end 183.09844 -127.632968)
		(width 0.127)
		(layer "In11.Cu")
		(net "FM_FORCE_PWRON_LVC3")
	)
	(segment
		(start 183.09844 -127.632968)
		(end 184.58434 -126.147068)
		(width 0.127)
		(layer "In11.Cu")
		(net "FM_FORCE_PWRON_LVC3")
	)
	(segment
		(start 184.58434 -121.572528)
		(end 184.55386 -121.542048)
		(width 0.127)
		(layer "In11.Cu")
		(net "FM_FORCE_PWRON_LVC3")
	)
	(segment
		(start 180.57876 -141.409928)
		(end 183.09844 -138.890248)
		(width 0.127)
		(layer "In11.Cu")
		(net "FM_FORCE_PWRON_LVC3")
	)
	(segment
		(start 184.58434 -126.147068)
		(end 184.58434 -121.572528)
		(width 0.127)
		(layer "In11.Cu")
		(net "FM_FORCE_PWRON_LVC3")
	)
	(segment
		(start 183.76138 -119.982488)
		(end 183.76138 -112.181132)
		(width 0.127)
		(layer "In11.Cu")
		(net "FM_FORCE_PWRON_LVC3")
	)
	(segment
		(start 184.55386 -120.360948)
		(end 184.3659 -120.172988)
		(width 0.127)
		(layer "In11.Cu")
		(net "FM_FORCE_PWRON_LVC3")
	)
	(segment
		(start 183.95188 -120.172988)
		(end 183.76138 -119.982488)
		(width 0.127)
		(layer "In11.Cu")
		(net "FM_FORCE_PWRON_LVC3")
	)
	(segment
		(start 129.175002 -154.195018)
		(end 130.398012 -152.972008)
		(width 0.127)
		(layer "In15.Cu")
		(net "FM_FORCE_PWRON_LVC3")
	)
	(segment
		(start 130.398012 -152.972008)
		(end 138.69162 -152.972008)
		(width 0.127)
		(layer "In15.Cu")
		(net "FM_FORCE_PWRON_LVC3")
	)
	(segment
		(start 138.69162 -152.972008)
		(end 141.50594 -150.157688)
		(width 0.127)
		(layer "In15.Cu")
		(net "FM_FORCE_PWRON_LVC3")
	)
	(segment
		(start 141.50594 -150.157688)
		(end 180.57876 -150.157688)
		(width 0.127)
		(layer "In15.Cu")
		(net "FM_FORCE_PWRON_LVC3")
	)
	(segment
		(start 317.84671 -43.4213)
		(end 315.138308 -43.4213)
		(width 0.12954)
		(layer "F.Cu")
		(net "FM_FLASH_SECURITY_STRAP")
	)
	(segment
		(start 312.894472 -42.763948)
		(end 312.843672 -42.713148)
		(width 0.12954)
		(layer "F.Cu")
		(net "FM_FLASH_SECURITY_STRAP")
	)
	(segment
		(start 310.538622 -42.916348)
		(end 310.955182 -43.332908)
		(width 0.12954)
		(layer "F.Cu")
		(net "FM_FLASH_SECURITY_STRAP")
	)
	(segment
		(start 319.11671 -44.6913)
		(end 317.84671 -43.4213)
		(width 0.12954)
		(layer "F.Cu")
		(net "FM_FLASH_SECURITY_STRAP")
	)
	(segment
		(start 309.922672 -42.916348)
		(end 310.538622 -42.916348)
		(width 0.12954)
		(layer "F.Cu")
		(net "FM_FLASH_SECURITY_STRAP")
	)
	(segment
		(start 325.778622 -45.949108)
		(end 325.158862 -45.329348)
		(width 0.0889)
		(layer "F.Cu")
		(net "FM_FLASH_SECURITY_STRAP")
	)
	(segment
		(start 315.138308 -43.4213)
		(end 314.480956 -42.763948)
		(width 0.12954)
		(layer "F.Cu")
		(net "FM_FLASH_SECURITY_STRAP")
	)
	(segment
		(start 322.575174 -45.612558)
		(end 320.08572 -45.612558)
		(width 0.12954)
		(layer "F.Cu")
		(net "FM_FLASH_SECURITY_STRAP")
	)
	(segment
		(start 312.223912 -43.332908)
		(end 312.843672 -42.713148)
		(width 0.12954)
		(layer "F.Cu")
		(net "FM_FLASH_SECURITY_STRAP")
	)
	(segment
		(start 326.584818 -45.949108)
		(end 325.778622 -45.949108)
		(width 0.0889)
		(layer "F.Cu")
		(net "FM_FLASH_SECURITY_STRAP")
	)
	(segment
		(start 319.164462 -44.6913)
		(end 319.11671 -44.6913)
		(width 0.12954)
		(layer "F.Cu")
		(net "FM_FLASH_SECURITY_STRAP")
	)
	(segment
		(start 323.365622 -45.329348)
		(end 323.082412 -45.612558)
		(width 0.0889)
		(layer "F.Cu")
		(net "FM_FLASH_SECURITY_STRAP")
	)
	(segment
		(start 314.480956 -42.763948)
		(end 314.0202 -42.763948)
		(width 0.12954)
		(layer "F.Cu")
		(net "FM_FLASH_SECURITY_STRAP")
	)
	(segment
		(start 323.082412 -45.612558)
		(end 322.575174 -45.612558)
		(width 0.0889)
		(layer "F.Cu")
		(net "FM_FLASH_SECURITY_STRAP")
	)
	(segment
		(start 325.158862 -45.329348)
		(end 323.365622 -45.329348)
		(width 0.0889)
		(layer "F.Cu")
		(net "FM_FLASH_SECURITY_STRAP")
	)
	(segment
		(start 314.0202 -42.763948)
		(end 312.894472 -42.763948)
		(width 0.12954)
		(layer "F.Cu")
		(net "FM_FLASH_SECURITY_STRAP")
	)
	(segment
		(start 310.955182 -43.332908)
		(end 312.223912 -43.332908)
		(width 0.12954)
		(layer "F.Cu")
		(net "FM_FLASH_SECURITY_STRAP")
	)
	(segment
		(start 320.08572 -45.612558)
		(end 319.164462 -44.6913)
		(width 0.12954)
		(layer "F.Cu")
		(net "FM_FLASH_SECURITY_STRAP")
	)
	(via
		(at 314.0202 -42.763948)
		(size 0.762)
		(drill 0.381)
		(layers "F.Cu" "B.Cu")
		(net "FM_FLASH_SECURITY_STRAP")
	)
	(via
		(at 310.538622 -42.916348)
		(size 0.508)
		(drill 0.254)
		(layers "F.Cu" "B.Cu")
		(net "FM_FLASH_SECURITY_STRAP")
	)
	(segment
		(start 348.996 -37.871908)
		(end 348.996 -41.618408)
		(width 0.127)
		(layer "In15.Cu")
		(net "FM_FLASH_SECURITY_STRAP")
	)
	(segment
		(start 424.26128 -28.039568)
		(end 429.91024 -28.039568)
		(width 0.127)
		(layer "In15.Cu")
		(net "FM_FLASH_SECURITY_STRAP")
	)
	(segment
		(start 332.69682 -35.519868)
		(end 341.8205 -35.519868)
		(width 0.127)
		(layer "In15.Cu")
		(net "FM_FLASH_SECURITY_STRAP")
	)
	(segment
		(start 346.096336 -36.121848)
		(end 348.05874 -36.934648)
		(width 0.127)
		(layer "In15.Cu")
		(net "FM_FLASH_SECURITY_STRAP")
	)
	(segment
		(start 325.77786 -38.920928)
		(end 326.79132 -37.907468)
		(width 0.127)
		(layer "In15.Cu")
		(net "FM_FLASH_SECURITY_STRAP")
	)
	(segment
		(start 355.73208 -48.354488)
		(end 371.76456 -48.354488)
		(width 0.127)
		(layer "In15.Cu")
		(net "FM_FLASH_SECURITY_STRAP")
	)
	(segment
		(start 429.16983 -34.459926)
		(end 429.170084 -34.459926)
		(width 0.127)
		(layer "In15.Cu")
		(net "FM_FLASH_SECURITY_STRAP")
	)
	(segment
		(start 330.23048 -37.076888)
		(end 331.1398 -37.076888)
		(width 0.127)
		(layer "In15.Cu")
		(net "FM_FLASH_SECURITY_STRAP")
	)
	(segment
		(start 430.80686 -28.936188)
		(end 430.80686 -32.822896)
		(width 0.127)
		(layer "In15.Cu")
		(net "FM_FLASH_SECURITY_STRAP")
	)
	(segment
		(start 326.79132 -37.907468)
		(end 329.3999 -37.907468)
		(width 0.127)
		(layer "In15.Cu")
		(net "FM_FLASH_SECURITY_STRAP")
	)
	(segment
		(start 342.42248 -36.121848)
		(end 346.096336 -36.121848)
		(width 0.127)
		(layer "In15.Cu")
		(net "FM_FLASH_SECURITY_STRAP")
	)
	(segment
		(start 331.1398 -37.076888)
		(end 332.69682 -35.519868)
		(width 0.127)
		(layer "In15.Cu")
		(net "FM_FLASH_SECURITY_STRAP")
	)
	(segment
		(start 371.76456 -48.354488)
		(end 375.40946 -44.709588)
		(width 0.127)
		(layer "In15.Cu")
		(net "FM_FLASH_SECURITY_STRAP")
	)
	(segment
		(start 311.333642 -42.121328)
		(end 312.30062 -42.121328)
		(width 0.127)
		(layer "In15.Cu")
		(net "FM_FLASH_SECURITY_STRAP")
	)
	(segment
		(start 415.77006 -36.530788)
		(end 424.26128 -28.039568)
		(width 0.127)
		(layer "In15.Cu")
		(net "FM_FLASH_SECURITY_STRAP")
	)
	(segment
		(start 429.91024 -28.039568)
		(end 430.80686 -28.936188)
		(width 0.127)
		(layer "In15.Cu")
		(net "FM_FLASH_SECURITY_STRAP")
	)
	(segment
		(start 312.30062 -42.121328)
		(end 315.50102 -38.920928)
		(width 0.127)
		(layer "In15.Cu")
		(net "FM_FLASH_SECURITY_STRAP")
	)
	(segment
		(start 430.80686 -32.822896)
		(end 429.16983 -34.459926)
		(width 0.127)
		(layer "In15.Cu")
		(net "FM_FLASH_SECURITY_STRAP")
	)
	(segment
		(start 348.05874 -36.934648)
		(end 348.996 -37.871908)
		(width 0.127)
		(layer "In15.Cu")
		(net "FM_FLASH_SECURITY_STRAP")
	)
	(segment
		(start 401.19046 -36.530788)
		(end 415.77006 -36.530788)
		(width 0.127)
		(layer "In15.Cu")
		(net "FM_FLASH_SECURITY_STRAP")
	)
	(segment
		(start 329.3999 -37.907468)
		(end 330.23048 -37.076888)
		(width 0.127)
		(layer "In15.Cu")
		(net "FM_FLASH_SECURITY_STRAP")
	)
	(segment
		(start 341.8205 -35.519868)
		(end 342.42248 -36.121848)
		(width 0.127)
		(layer "In15.Cu")
		(net "FM_FLASH_SECURITY_STRAP")
	)
	(segment
		(start 393.01166 -44.709588)
		(end 401.19046 -36.530788)
		(width 0.127)
		(layer "In15.Cu")
		(net "FM_FLASH_SECURITY_STRAP")
	)
	(segment
		(start 315.50102 -38.920928)
		(end 325.77786 -38.920928)
		(width 0.127)
		(layer "In15.Cu")
		(net "FM_FLASH_SECURITY_STRAP")
	)
	(segment
		(start 375.40946 -44.709588)
		(end 393.01166 -44.709588)
		(width 0.127)
		(layer "In15.Cu")
		(net "FM_FLASH_SECURITY_STRAP")
	)
	(segment
		(start 348.996 -41.618408)
		(end 355.73208 -48.354488)
		(width 0.127)
		(layer "In15.Cu")
		(net "FM_FLASH_SECURITY_STRAP")
	)
	(segment
		(start 310.538622 -42.916348)
		(end 311.333642 -42.121328)
		(width 0.127)
		(layer "In15.Cu")
		(net "FM_FLASH_SECURITY_STRAP")
	)
	(segment
		(start 332.422246 -43.281346)
		(end 331.883004 -43.281346)
		(width 0.12954)
		(layer "F.Cu")
		(net "FM_EUP_LOT6_N")
	)
	(via
		(at 331.883004 -43.281346)
		(size 0.4572)
		(drill 0.2032)
		(layers "F.Cu" "B.Cu")
		(net "FM_EUP_LOT6_N")
	)
	(via
		(at 328.396346 -25.023826)
		(size 0.508)
		(drill 0.254)
		(layers "F.Cu" "B.Cu")
		(net "FM_EUP_LOT6_N")
	)
	(segment
		(start 328.396346 -25.023826)
		(end 327.060814 -26.359358)
		(width 0.12954)
		(layer "B.Cu")
		(net "FM_EUP_LOT6_N")
	)
	(segment
		(start 327.060814 -26.359358)
		(end 327.060814 -28.44292)
		(width 0.12954)
		(layer "B.Cu")
		(net "FM_EUP_LOT6_N")
	)
	(segment
		(start 331.47508 -38.656768)
		(end 332.5876 -37.544248)
		(width 0.127)
		(layer "In2.Cu")
		(net "FM_EUP_LOT6_N")
	)
	(segment
		(start 328.779378 -25.023826)
		(end 328.396346 -25.023826)
		(width 0.127)
		(layer "In2.Cu")
		(net "FM_EUP_LOT6_N")
	)
	(segment
		(start 331.883004 -43.281346)
		(end 331.47508 -42.873422)
		(width 0.127)
		(layer "In2.Cu")
		(net "FM_EUP_LOT6_N")
	)
	(segment
		(start 332.5876 -28.832048)
		(end 328.779378 -25.023826)
		(width 0.127)
		(layer "In2.Cu")
		(net "FM_EUP_LOT6_N")
	)
	(segment
		(start 332.5876 -37.544248)
		(end 332.5876 -28.832048)
		(width 0.127)
		(layer "In2.Cu")
		(net "FM_EUP_LOT6_N")
	)
	(segment
		(start 331.47508 -42.873422)
		(end 331.47508 -38.656768)
		(width 0.127)
		(layer "In2.Cu")
		(net "FM_EUP_LOT6_N")
	)
	(segment
		(start 335.209134 -18.39722)
		(end 335.303876 -18.302478)
		(width 0.12954)
		(layer "F.Cu")
		(net "FM_ESPI_PLD_R_EN_BUF")
	)
	(segment
		(start 331.61732 -15.314168)
		(end 331.27696 -14.973808)
		(width 0.12954)
		(layer "F.Cu")
		(net "FM_ESPI_PLD_R_EN_BUF")
	)
	(segment
		(start 334.729074 -15.303246)
		(end 334.729074 -15.80515)
		(width 0.12954)
		(layer "F.Cu")
		(net "FM_ESPI_PLD_R_EN_BUF")
	)
	(segment
		(start 334.380586 -14.954758)
		(end 334.729074 -15.303246)
		(width 0.12954)
		(layer "F.Cu")
		(net "FM_ESPI_PLD_R_EN_BUF")
	)
	(segment
		(start 334.380586 -14.954758)
		(end 334.021176 -15.314168)
		(width 0.12954)
		(layer "F.Cu")
		(net "FM_ESPI_PLD_R_EN_BUF")
	)
	(segment
		(start 334.380586 -14.909038)
		(end 334.380586 -14.954758)
		(width 0.12954)
		(layer "F.Cu")
		(net "FM_ESPI_PLD_R_EN_BUF")
	)
	(segment
		(start 165.96868 -31.333948)
		(end 166.41699 -30.885638)
		(width 0.12954)
		(layer "F.Cu")
		(net "FM_ESPI_PLD_R_EN_BUF")
	)
	(segment
		(start 165.68928 -31.333948)
		(end 165.96868 -31.333948)
		(width 0.12954)
		(layer "F.Cu")
		(net "FM_ESPI_PLD_R_EN_BUF")
	)
	(segment
		(start 331.434186 -13.335762)
		(end 331.798676 -13.335762)
		(width 0.12954)
		(layer "F.Cu")
		(net "FM_ESPI_PLD_R_EN_BUF")
	)
	(segment
		(start 334.021176 -15.314168)
		(end 331.61732 -15.314168)
		(width 0.12954)
		(layer "F.Cu")
		(net "FM_ESPI_PLD_R_EN_BUF")
	)
	(segment
		(start 331.27696 -14.973808)
		(end 331.27696 -13.492988)
		(width 0.12954)
		(layer "F.Cu")
		(net "FM_ESPI_PLD_R_EN_BUF")
	)
	(segment
		(start 331.27696 -13.492988)
		(end 331.434186 -13.335762)
		(width 0.12954)
		(layer "F.Cu")
		(net "FM_ESPI_PLD_R_EN_BUF")
	)
	(segment
		(start 166.41699 -30.885638)
		(end 166.41699 -30.584648)
		(width 0.12954)
		(layer "F.Cu")
		(net "FM_ESPI_PLD_R_EN_BUF")
	)
	(segment
		(start 335.009998 -15.80515)
		(end 334.729074 -15.80515)
		(width 0.12954)
		(layer "F.Cu")
		(net "FM_ESPI_PLD_R_EN_BUF")
	)
	(segment
		(start 335.303876 -16.099028)
		(end 335.009998 -15.80515)
		(width 0.12954)
		(layer "F.Cu")
		(net "FM_ESPI_PLD_R_EN_BUF")
	)
	(segment
		(start 335.303876 -18.302478)
		(end 335.303876 -16.099028)
		(width 0.12954)
		(layer "F.Cu")
		(net "FM_ESPI_PLD_R_EN_BUF")
	)
	(via
		(at 165.68928 -31.333948)
		(size 0.508)
		(drill 0.254)
		(layers "F.Cu" "B.Cu")
		(net "FM_ESPI_PLD_R_EN_BUF")
	)
	(via
		(at 334.380586 -14.909038)
		(size 0.508)
		(drill 0.254)
		(layers "F.Cu" "B.Cu")
		(net "FM_ESPI_PLD_R_EN_BUF")
	)
	(via
		(at 166.8653 -14.989048)
		(size 0.508)
		(drill 0.254)
		(layers "F.Cu" "B.Cu")
		(net "FM_ESPI_PLD_R_EN_BUF")
	)
	(segment
		(start 297.632882 -21.935948)
		(end 303.855882 -15.712948)
		(width 0.127)
		(layer "In11.Cu")
		(net "FM_ESPI_PLD_R_EN_BUF")
	)
	(segment
		(start 334.334866 -14.909038)
		(end 334.380586 -14.909038)
		(width 0.127)
		(layer "In11.Cu")
		(net "FM_ESPI_PLD_R_EN_BUF")
	)
	(segment
		(start 266.698984 -33.820608)
		(end 278.583644 -21.935948)
		(width 0.127)
		(layer "In11.Cu")
		(net "FM_ESPI_PLD_R_EN_BUF")
	)
	(segment
		(start 166.8653 -14.989048)
		(end 170.484038 -14.989048)
		(width 0.127)
		(layer "In11.Cu")
		(net "FM_ESPI_PLD_R_EN_BUF")
	)
	(segment
		(start 241.733324 -43.056048)
		(end 244.206268 -40.583104)
		(width 0.127)
		(layer "In11.Cu")
		(net "FM_ESPI_PLD_R_EN_BUF")
	)
	(segment
		(start 303.855882 -15.712948)
		(end 319.570862 -15.712948)
		(width 0.127)
		(layer "In11.Cu")
		(net "FM_ESPI_PLD_R_EN_BUF")
	)
	(segment
		(start 199.530462 -28.29687)
		(end 201.537316 -28.29687)
		(width 0.127)
		(layer "In11.Cu")
		(net "FM_ESPI_PLD_R_EN_BUF")
	)
	(segment
		(start 191.086994 -16.319246)
		(end 196.398896 -21.631148)
		(width 0.127)
		(layer "In11.Cu")
		(net "FM_ESPI_PLD_R_EN_BUF")
	)
	(segment
		(start 319.570862 -15.712948)
		(end 321.575176 -13.708634)
		(width 0.127)
		(layer "In11.Cu")
		(net "FM_ESPI_PLD_R_EN_BUF")
	)
	(segment
		(start 333.134462 -13.708634)
		(end 334.334866 -14.909038)
		(width 0.127)
		(layer "In11.Cu")
		(net "FM_ESPI_PLD_R_EN_BUF")
	)
	(segment
		(start 196.398896 -25.165304)
		(end 199.530462 -28.29687)
		(width 0.127)
		(layer "In11.Cu")
		(net "FM_ESPI_PLD_R_EN_BUF")
	)
	(segment
		(start 252.71603 -40.583104)
		(end 253.636526 -39.662608)
		(width 0.127)
		(layer "In11.Cu")
		(net "FM_ESPI_PLD_R_EN_BUF")
	)
	(segment
		(start 201.537316 -28.29687)
		(end 204.565758 -31.325312)
		(width 0.127)
		(layer "In11.Cu")
		(net "FM_ESPI_PLD_R_EN_BUF")
	)
	(segment
		(start 255.825244 -39.662608)
		(end 256.750312 -38.73754)
		(width 0.127)
		(layer "In11.Cu")
		(net "FM_ESPI_PLD_R_EN_BUF")
	)
	(segment
		(start 256.750312 -38.73754)
		(end 258.17068 -38.73754)
		(width 0.127)
		(layer "In11.Cu")
		(net "FM_ESPI_PLD_R_EN_BUF")
	)
	(segment
		(start 244.206268 -40.583104)
		(end 252.71603 -40.583104)
		(width 0.127)
		(layer "In11.Cu")
		(net "FM_ESPI_PLD_R_EN_BUF")
	)
	(segment
		(start 196.398896 -21.631148)
		(end 196.398896 -25.165304)
		(width 0.127)
		(layer "In11.Cu")
		(net "FM_ESPI_PLD_R_EN_BUF")
	)
	(segment
		(start 221.136464 -38.123114)
		(end 222.97771 -38.123114)
		(width 0.127)
		(layer "In11.Cu")
		(net "FM_ESPI_PLD_R_EN_BUF")
	)
	(segment
		(start 221.04731 -38.03396)
		(end 221.136464 -38.123114)
		(width 0.127)
		(layer "In11.Cu")
		(net "FM_ESPI_PLD_R_EN_BUF")
	)
	(segment
		(start 321.575176 -13.708634)
		(end 333.134462 -13.708634)
		(width 0.127)
		(layer "In11.Cu")
		(net "FM_ESPI_PLD_R_EN_BUF")
	)
	(segment
		(start 253.636526 -39.662608)
		(end 255.825244 -39.662608)
		(width 0.127)
		(layer "In11.Cu")
		(net "FM_ESPI_PLD_R_EN_BUF")
	)
	(segment
		(start 204.565758 -31.325312)
		(end 209.760566 -31.325312)
		(width 0.127)
		(layer "In11.Cu")
		(net "FM_ESPI_PLD_R_EN_BUF")
	)
	(segment
		(start 171.814236 -16.319246)
		(end 191.086994 -16.319246)
		(width 0.127)
		(layer "In11.Cu")
		(net "FM_ESPI_PLD_R_EN_BUF")
	)
	(segment
		(start 170.484038 -14.989048)
		(end 171.814236 -16.319246)
		(width 0.127)
		(layer "In11.Cu")
		(net "FM_ESPI_PLD_R_EN_BUF")
	)
	(segment
		(start 263.087612 -33.820608)
		(end 266.698984 -33.820608)
		(width 0.127)
		(layer "In11.Cu")
		(net "FM_ESPI_PLD_R_EN_BUF")
	)
	(segment
		(start 216.469214 -38.03396)
		(end 221.04731 -38.03396)
		(width 0.127)
		(layer "In11.Cu")
		(net "FM_ESPI_PLD_R_EN_BUF")
	)
	(segment
		(start 222.97771 -38.123114)
		(end 224.71761 -39.863014)
		(width 0.127)
		(layer "In11.Cu")
		(net "FM_ESPI_PLD_R_EN_BUF")
	)
	(segment
		(start 230.721154 -39.863014)
		(end 233.914188 -43.056048)
		(width 0.127)
		(layer "In11.Cu")
		(net "FM_ESPI_PLD_R_EN_BUF")
	)
	(segment
		(start 233.914188 -43.056048)
		(end 241.733324 -43.056048)
		(width 0.127)
		(layer "In11.Cu")
		(net "FM_ESPI_PLD_R_EN_BUF")
	)
	(segment
		(start 258.17068 -38.73754)
		(end 263.087612 -33.820608)
		(width 0.127)
		(layer "In11.Cu")
		(net "FM_ESPI_PLD_R_EN_BUF")
	)
	(segment
		(start 209.760566 -31.325312)
		(end 216.469214 -38.03396)
		(width 0.127)
		(layer "In11.Cu")
		(net "FM_ESPI_PLD_R_EN_BUF")
	)
	(segment
		(start 224.71761 -39.863014)
		(end 230.721154 -39.863014)
		(width 0.127)
		(layer "In11.Cu")
		(net "FM_ESPI_PLD_R_EN_BUF")
	)
	(segment
		(start 278.583644 -21.935948)
		(end 297.632882 -21.935948)
		(width 0.127)
		(layer "In11.Cu")
		(net "FM_ESPI_PLD_R_EN_BUF")
	)
	(segment
		(start 163.88334 -20.889468)
		(end 164.86632 -19.906488)
		(width 0.127)
		(layer "In15.Cu")
		(net "FM_ESPI_PLD_R_EN_BUF")
	)
	(segment
		(start 165.68928 -31.333948)
		(end 165.68928 -27.374088)
		(width 0.127)
		(layer "In15.Cu")
		(net "FM_ESPI_PLD_R_EN_BUF")
	)
	(segment
		(start 165.68928 -27.374088)
		(end 163.88334 -25.568148)
		(width 0.127)
		(layer "In15.Cu")
		(net "FM_ESPI_PLD_R_EN_BUF")
	)
	(segment
		(start 163.88334 -25.568148)
		(end 163.88334 -20.889468)
		(width 0.127)
		(layer "In15.Cu")
		(net "FM_ESPI_PLD_R_EN_BUF")
	)
	(segment
		(start 164.86632 -16.988028)
		(end 166.8653 -14.989048)
		(width 0.127)
		(layer "In15.Cu")
		(net "FM_ESPI_PLD_R_EN_BUF")
	)
	(segment
		(start 164.86632 -19.906488)
		(end 164.86632 -16.988028)
		(width 0.127)
		(layer "In15.Cu")
		(net "FM_ESPI_PLD_R_EN_BUF")
	)
	(segment
		(start 174.955708 -119.375428)
		(end 174.555658 -119.775478)
		(width 0.12954)
		(layer "F.Cu")
		(net "FM_ESPI_PLD_R_EN")
	)
	(segment
		(start 330.824586 -15.110714)
		(end 330.824586 -16.401288)
		(width 0.12954)
		(layer "F.Cu")
		(net "FM_ESPI_PLD_R_EN")
	)
	(segment
		(start 330.66228 -14.902688)
		(end 330.66228 -14.948408)
		(width 0.12954)
		(layer "F.Cu")
		(net "FM_ESPI_PLD_R_EN")
	)
	(segment
		(start 330.66228 -14.948408)
		(end 330.824586 -15.110714)
		(width 0.12954)
		(layer "F.Cu")
		(net "FM_ESPI_PLD_R_EN")
	)
	(via
		(at 294.50284 -92.97035)
		(size 0.762)
		(drill 0.254)
		(layers "F.Cu" "B.Cu")
		(net "FM_ESPI_PLD_R_EN")
	)
	(via
		(at 330.66228 -14.902688)
		(size 0.508)
		(drill 0.254)
		(layers "F.Cu" "B.Cu")
		(net "FM_ESPI_PLD_R_EN")
	)
	(via
		(at 174.555658 -119.775478)
		(size 0.4572)
		(drill 0.254)
		(layers "F.Cu" "B.Cu")
		(net "FM_ESPI_PLD_R_EN")
	)
	(segment
		(start 288.81324 -32.201104)
		(end 299.54474 -42.932604)
		(width 0.127)
		(layer "In2.Cu")
		(net "FM_ESPI_PLD_R_EN")
	)
	(segment
		(start 299.54474 -77.294486)
		(end 299.54474 -79.665068)
		(width 0.127)
		(layer "In2.Cu")
		(net "FM_ESPI_PLD_R_EN")
	)
	(segment
		(start 297.260518 -14.453616)
		(end 291.975032 -14.453616)
		(width 0.127)
		(layer "In2.Cu")
		(net "FM_ESPI_PLD_R_EN")
	)
	(segment
		(start 295.230042 -92.243148)
		(end 294.50284 -92.97035)
		(width 0.127)
		(layer "In2.Cu")
		(net "FM_ESPI_PLD_R_EN")
	)
	(segment
		(start 299.54474 -79.665068)
		(end 295.230042 -83.979766)
		(width 0.127)
		(layer "In2.Cu")
		(net "FM_ESPI_PLD_R_EN")
	)
	(segment
		(start 311.802272 -15.876016)
		(end 309.402734 -13.476478)
		(width 0.127)
		(layer "In2.Cu")
		(net "FM_ESPI_PLD_R_EN")
	)
	(segment
		(start 330.66228 -14.902688)
		(end 330.61656 -14.902688)
		(width 0.127)
		(layer "In2.Cu")
		(net "FM_ESPI_PLD_R_EN")
	)
	(segment
		(start 314.38215 -15.876016)
		(end 311.802272 -15.876016)
		(width 0.127)
		(layer "In2.Cu")
		(net "FM_ESPI_PLD_R_EN")
	)
	(segment
		(start 329.916282 -14.20241)
		(end 322.627752 -14.20241)
		(width 0.127)
		(layer "In2.Cu")
		(net "FM_ESPI_PLD_R_EN")
	)
	(segment
		(start 291.975032 -14.453616)
		(end 288.81324 -17.615408)
		(width 0.127)
		(layer "In2.Cu")
		(net "FM_ESPI_PLD_R_EN")
	)
	(segment
		(start 322.627752 -14.20241)
		(end 321.921378 -14.908784)
		(width 0.127)
		(layer "In2.Cu")
		(net "FM_ESPI_PLD_R_EN")
	)
	(segment
		(start 295.230042 -83.979766)
		(end 295.230042 -92.243148)
		(width 0.127)
		(layer "In2.Cu")
		(net "FM_ESPI_PLD_R_EN")
	)
	(segment
		(start 301.74692 -63.056008)
		(end 301.74692 -74.008488)
		(width 0.127)
		(layer "In2.Cu")
		(net "FM_ESPI_PLD_R_EN")
	)
	(segment
		(start 330.61656 -14.902688)
		(end 329.916282 -14.20241)
		(width 0.127)
		(layer "In2.Cu")
		(net "FM_ESPI_PLD_R_EN")
	)
	(segment
		(start 321.921378 -14.908784)
		(end 315.349382 -14.908784)
		(width 0.127)
		(layer "In2.Cu")
		(net "FM_ESPI_PLD_R_EN")
	)
	(segment
		(start 309.402734 -13.476478)
		(end 298.237656 -13.476478)
		(width 0.127)
		(layer "In2.Cu")
		(net "FM_ESPI_PLD_R_EN")
	)
	(segment
		(start 288.81324 -17.615408)
		(end 288.81324 -32.201104)
		(width 0.127)
		(layer "In2.Cu")
		(net "FM_ESPI_PLD_R_EN")
	)
	(segment
		(start 301.74692 -74.008488)
		(end 300.311058 -75.44435)
		(width 0.127)
		(layer "In2.Cu")
		(net "FM_ESPI_PLD_R_EN")
	)
	(segment
		(start 299.54474 -42.932604)
		(end 299.54474 -60.853828)
		(width 0.127)
		(layer "In2.Cu")
		(net "FM_ESPI_PLD_R_EN")
	)
	(segment
		(start 300.311058 -75.44435)
		(end 299.54474 -77.294486)
		(width 0.127)
		(layer "In2.Cu")
		(net "FM_ESPI_PLD_R_EN")
	)
	(segment
		(start 298.237656 -13.476478)
		(end 297.260518 -14.453616)
		(width 0.127)
		(layer "In2.Cu")
		(net "FM_ESPI_PLD_R_EN")
	)
	(segment
		(start 315.349382 -14.908784)
		(end 314.38215 -15.876016)
		(width 0.127)
		(layer "In2.Cu")
		(net "FM_ESPI_PLD_R_EN")
	)
	(segment
		(start 299.54474 -60.853828)
		(end 301.74692 -63.056008)
		(width 0.127)
		(layer "In2.Cu")
		(net "FM_ESPI_PLD_R_EN")
	)
	(segment
		(start 289.647122 -85.70595)
		(end 246.043958 -85.70595)
		(width 0.127)
		(layer "In13.Cu")
		(net "FM_ESPI_PLD_R_EN")
	)
	(segment
		(start 246.043958 -85.70595)
		(end 240.101374 -91.648534)
		(width 0.127)
		(layer "In13.Cu")
		(net "FM_ESPI_PLD_R_EN")
	)
	(segment
		(start 186.3598 -93.2688)
		(end 185.801 -93.8276)
		(width 0.127)
		(layer "In13.Cu")
		(net "FM_ESPI_PLD_R_EN")
	)
	(segment
		(start 181.102 -94.488)
		(end 178.2064 -94.488)
		(width 0.127)
		(layer "In13.Cu")
		(net "FM_ESPI_PLD_R_EN")
	)
	(segment
		(start 240.101374 -91.648534)
		(end 220.951806 -91.648534)
		(width 0.127)
		(layer "In13.Cu")
		(net "FM_ESPI_PLD_R_EN")
	)
	(segment
		(start 172.7962 -97.10293)
		(end 173.73981 -98.04654)
		(width 0.127)
		(layer "In13.Cu")
		(net "FM_ESPI_PLD_R_EN")
	)
	(segment
		(start 177.673 -93.9546)
		(end 175.3108 -93.9546)
		(width 0.127)
		(layer "In13.Cu")
		(net "FM_ESPI_PLD_R_EN")
	)
	(segment
		(start 174.08652 -100.942648)
		(end 174.08652 -101.829108)
		(width 0.127)
		(layer "In13.Cu")
		(net "FM_ESPI_PLD_R_EN")
	)
	(segment
		(start 295.126918 -92.346272)
		(end 295.126918 -91.185746)
		(width 0.127)
		(layer "In13.Cu")
		(net "FM_ESPI_PLD_R_EN")
	)
	(segment
		(start 294.50284 -92.97035)
		(end 295.126918 -92.346272)
		(width 0.127)
		(layer "In13.Cu")
		(net "FM_ESPI_PLD_R_EN")
	)
	(segment
		(start 181.7624 -93.8276)
		(end 181.102 -94.488)
		(width 0.127)
		(layer "In13.Cu")
		(net "FM_ESPI_PLD_R_EN")
	)
	(segment
		(start 295.126918 -91.185746)
		(end 289.647122 -85.70595)
		(width 0.127)
		(layer "In13.Cu")
		(net "FM_ESPI_PLD_R_EN")
	)
	(segment
		(start 173.5836 -95.0722)
		(end 173.5836 -95.320866)
		(width 0.127)
		(layer "In13.Cu")
		(net "FM_ESPI_PLD_R_EN")
	)
	(segment
		(start 174.95012 -104.945688)
		(end 174.95012 -119.381016)
		(width 0.127)
		(layer "In13.Cu")
		(net "FM_ESPI_PLD_R_EN")
	)
	(segment
		(start 173.5836 -95.320866)
		(end 172.7962 -96.108266)
		(width 0.127)
		(layer "In13.Cu")
		(net "FM_ESPI_PLD_R_EN")
	)
	(segment
		(start 174.95012 -119.381016)
		(end 174.555658 -119.775478)
		(width 0.127)
		(layer "In13.Cu")
		(net "FM_ESPI_PLD_R_EN")
	)
	(segment
		(start 175.3108 -93.9546)
		(end 174.3964 -94.869)
		(width 0.127)
		(layer "In13.Cu")
		(net "FM_ESPI_PLD_R_EN")
	)
	(segment
		(start 174.97806 -98.04654)
		(end 175.38192 -98.4504)
		(width 0.127)
		(layer "In13.Cu")
		(net "FM_ESPI_PLD_R_EN")
	)
	(segment
		(start 186.3598 -91.821)
		(end 186.3598 -93.2688)
		(width 0.127)
		(layer "In13.Cu")
		(net "FM_ESPI_PLD_R_EN")
	)
	(segment
		(start 173.73981 -98.04654)
		(end 174.97806 -98.04654)
		(width 0.127)
		(layer "In13.Cu")
		(net "FM_ESPI_PLD_R_EN")
	)
	(segment
		(start 174.52848 -104.524048)
		(end 174.95012 -104.945688)
		(width 0.127)
		(layer "In13.Cu")
		(net "FM_ESPI_PLD_R_EN")
	)
	(segment
		(start 175.38192 -98.4504)
		(end 175.38192 -99.647248)
		(width 0.127)
		(layer "In13.Cu")
		(net "FM_ESPI_PLD_R_EN")
	)
	(segment
		(start 220.951806 -91.648534)
		(end 216.27084 -86.967568)
		(width 0.127)
		(layer "In13.Cu")
		(net "FM_ESPI_PLD_R_EN")
	)
	(segment
		(start 174.08652 -101.829108)
		(end 174.52848 -102.271068)
		(width 0.127)
		(layer "In13.Cu")
		(net "FM_ESPI_PLD_R_EN")
	)
	(segment
		(start 175.38192 -99.647248)
		(end 174.08652 -100.942648)
		(width 0.127)
		(layer "In13.Cu")
		(net "FM_ESPI_PLD_R_EN")
	)
	(segment
		(start 191.213232 -86.967568)
		(end 186.3598 -91.821)
		(width 0.127)
		(layer "In13.Cu")
		(net "FM_ESPI_PLD_R_EN")
	)
	(segment
		(start 185.801 -93.8276)
		(end 181.7624 -93.8276)
		(width 0.127)
		(layer "In13.Cu")
		(net "FM_ESPI_PLD_R_EN")
	)
	(segment
		(start 216.27084 -86.967568)
		(end 191.213232 -86.967568)
		(width 0.127)
		(layer "In13.Cu")
		(net "FM_ESPI_PLD_R_EN")
	)
	(segment
		(start 178.2064 -94.488)
		(end 177.673 -93.9546)
		(width 0.127)
		(layer "In13.Cu")
		(net "FM_ESPI_PLD_R_EN")
	)
	(segment
		(start 172.7962 -96.108266)
		(end 172.7962 -97.10293)
		(width 0.127)
		(layer "In13.Cu")
		(net "FM_ESPI_PLD_R_EN")
	)
	(segment
		(start 174.3964 -94.869)
		(end 173.7868 -94.869)
		(width 0.127)
		(layer "In13.Cu")
		(net "FM_ESPI_PLD_R_EN")
	)
	(segment
		(start 174.52848 -102.271068)
		(end 174.52848 -104.524048)
		(width 0.127)
		(layer "In13.Cu")
		(net "FM_ESPI_PLD_R_EN")
	)
	(segment
		(start 173.7868 -94.869)
		(end 173.5836 -95.0722)
		(width 0.127)
		(layer "In13.Cu")
		(net "FM_ESPI_PLD_R_EN")
	)
	(segment
		(start 332.220824 -15.80515)
		(end 331.624686 -16.401288)
		(width 0.12954)
		(layer "F.Cu")
		(net "FM_ESPI_PLD_R1_EN")
	)
	(segment
		(start 329.55738 -13.985748)
		(end 329.898756 -13.985748)
		(width 0.12954)
		(layer "F.Cu")
		(net "FM_ESPI_PLD_R1_EN")
	)
	(segment
		(start 332.68666 -15.80515)
		(end 332.220824 -15.80515)
		(width 0.12954)
		(layer "F.Cu")
		(net "FM_ESPI_PLD_R1_EN")
	)
	(segment
		(start 331.150976 -16.874998)
		(end 331.624686 -16.401288)
		(width 0.12954)
		(layer "F.Cu")
		(net "FM_ESPI_PLD_R1_EN")
	)
	(segment
		(start 332.68666 -15.80515)
		(end 333.702152 -15.80515)
		(width 0.12954)
		(layer "F.Cu")
		(net "FM_ESPI_PLD_R1_EN")
	)
	(segment
		(start 329.331574 -14.211554)
		(end 329.55738 -13.985748)
		(width 0.12954)
		(layer "F.Cu")
		(net "FM_ESPI_PLD_R1_EN")
	)
	(segment
		(start 329.331574 -15.297658)
		(end 329.331574 -14.211554)
		(width 0.12954)
		(layer "F.Cu")
		(net "FM_ESPI_PLD_R1_EN")
	)
	(segment
		(start 330.824586 -17.414748)
		(end 329.61834 -17.414748)
		(width 0.12954)
		(layer "F.Cu")
		(net "FM_ESPI_PLD_R1_EN")
	)
	(segment
		(start 329.0316 -15.597632)
		(end 329.331574 -15.297658)
		(width 0.12954)
		(layer "F.Cu")
		(net "FM_ESPI_PLD_R1_EN")
	)
	(segment
		(start 330.824586 -17.414748)
		(end 331.150976 -17.088358)
		(width 0.12954)
		(layer "F.Cu")
		(net "FM_ESPI_PLD_R1_EN")
	)
	(segment
		(start 331.150976 -17.088358)
		(end 331.150976 -16.874998)
		(width 0.12954)
		(layer "F.Cu")
		(net "FM_ESPI_PLD_R1_EN")
	)
	(segment
		(start 329.0316 -16.828008)
		(end 329.0316 -15.597632)
		(width 0.12954)
		(layer "F.Cu")
		(net "FM_ESPI_PLD_R1_EN")
	)
	(segment
		(start 329.61834 -17.414748)
		(end 329.0316 -16.828008)
		(width 0.12954)
		(layer "F.Cu")
		(net "FM_ESPI_PLD_R1_EN")
	)
	(via
		(at 329.61834 -17.414748)
		(size 0.762)
		(drill 0.381)
		(layers "F.Cu" "B.Cu")
		(net "FM_ESPI_PLD_R1_EN")
	)
	(segment
		(start 335.035398 -20.607782)
		(end 335.035398 -19.371056)
		(width 0.12954)
		(layer "F.Cu")
		(net "FM_ESPI_PLD_EN")
	)
	(segment
		(start 337.575144 -19.28495)
		(end 337.792314 -19.06778)
		(width 0.12954)
		(layer "F.Cu")
		(net "FM_ESPI_PLD_EN")
	)
	(segment
		(start 335.234534 -19.17192)
		(end 335.89341 -19.17192)
		(width 0.12954)
		(layer "F.Cu")
		(net "FM_ESPI_PLD_EN")
	)
	(segment
		(start 335.035398 -19.371056)
		(end 335.209134 -19.19732)
		(width 0.12954)
		(layer "F.Cu")
		(net "FM_ESPI_PLD_EN")
	)
	(segment
		(start 337.792314 -19.06778)
		(end 337.792314 -18.434558)
		(width 0.12954)
		(layer "F.Cu")
		(net "FM_ESPI_PLD_EN")
	)
	(segment
		(start 335.89341 -19.17192)
		(end 336.00644 -19.28495)
		(width 0.12954)
		(layer "F.Cu")
		(net "FM_ESPI_PLD_EN")
	)
	(segment
		(start 336.00644 -19.28495)
		(end 337.575144 -19.28495)
		(width 0.12954)
		(layer "F.Cu")
		(net "FM_ESPI_PLD_EN")
	)
	(segment
		(start 335.209134 -19.19732)
		(end 335.234534 -19.17192)
		(width 0.12954)
		(layer "F.Cu")
		(net "FM_ESPI_PLD_EN")
	)
	(via
		(at 335.89341 -19.17192)
		(size 0.508)
		(drill 0.254)
		(layers "F.Cu" "B.Cu")
		(net "FM_ESPI_PLD_EN")
	)
	(segment
		(start 313.459876 -45.667168)
		(end 313.950096 -45.176948)
		(width 0.12954)
		(layer "F.Cu")
		(net "FM_ESPI_FLASH_MODE")
	)
	(segment
		(start 313.950096 -45.176948)
		(end 315.565282 -45.176948)
		(width 0.12954)
		(layer "F.Cu")
		(net "FM_ESPI_FLASH_MODE")
	)
	(segment
		(start 324.889622 -46.345348)
		(end 325.493888 -46.949614)
		(width 0.0889)
		(layer "F.Cu")
		(net "FM_ESPI_FLASH_MODE")
	)
	(segment
		(start 316.536578 -45.176948)
		(end 316.867286 -45.507656)
		(width 0.12954)
		(layer "F.Cu")
		(net "FM_ESPI_FLASH_MODE")
	)
	(segment
		(start 318.531494 -46.751748)
		(end 322.575174 -46.751748)
		(width 0.12954)
		(layer "F.Cu")
		(net "FM_ESPI_FLASH_MODE")
	)
	(segment
		(start 309.122572 -44.948348)
		(end 309.605172 -45.430948)
		(width 0.12954)
		(layer "F.Cu")
		(net "FM_ESPI_FLASH_MODE")
	)
	(segment
		(start 309.605172 -45.430948)
		(end 310.500776 -45.430948)
		(width 0.12954)
		(layer "F.Cu")
		(net "FM_ESPI_FLASH_MODE")
	)
	(segment
		(start 310.500776 -45.430948)
		(end 310.787796 -45.717968)
		(width 0.12954)
		(layer "F.Cu")
		(net "FM_ESPI_FLASH_MODE")
	)
	(segment
		(start 315.565282 -45.176948)
		(end 316.536578 -45.176948)
		(width 0.12954)
		(layer "F.Cu")
		(net "FM_ESPI_FLASH_MODE")
	)
	(segment
		(start 323.467222 -46.751748)
		(end 323.873622 -46.345348)
		(width 0.0889)
		(layer "F.Cu")
		(net "FM_ESPI_FLASH_MODE")
	)
	(segment
		(start 316.867286 -45.507656)
		(end 317.287402 -45.507656)
		(width 0.12954)
		(layer "F.Cu")
		(net "FM_ESPI_FLASH_MODE")
	)
	(segment
		(start 311.755536 -45.667168)
		(end 313.459876 -45.667168)
		(width 0.12954)
		(layer "F.Cu")
		(net "FM_ESPI_FLASH_MODE")
	)
	(segment
		(start 325.493888 -46.949614)
		(end 326.584818 -46.949614)
		(width 0.0889)
		(layer "F.Cu")
		(net "FM_ESPI_FLASH_MODE")
	)
	(segment
		(start 322.575174 -46.751748)
		(end 323.467222 -46.751748)
		(width 0.0889)
		(layer "F.Cu")
		(net "FM_ESPI_FLASH_MODE")
	)
	(segment
		(start 317.287402 -45.507656)
		(end 318.531494 -46.751748)
		(width 0.12954)
		(layer "F.Cu")
		(net "FM_ESPI_FLASH_MODE")
	)
	(segment
		(start 310.787796 -45.717968)
		(end 311.704736 -45.717968)
		(width 0.12954)
		(layer "F.Cu")
		(net "FM_ESPI_FLASH_MODE")
	)
	(segment
		(start 311.704736 -45.717968)
		(end 311.755536 -45.667168)
		(width 0.12954)
		(layer "F.Cu")
		(net "FM_ESPI_FLASH_MODE")
	)
	(segment
		(start 323.873622 -46.345348)
		(end 324.889622 -46.345348)
		(width 0.0889)
		(layer "F.Cu")
		(net "FM_ESPI_FLASH_MODE")
	)
	(segment
		(start 309.122572 -44.948348)
		(end 307.763672 -44.948348)
		(width 0.12954)
		(layer "F.Cu")
		(net "FM_ESPI_FLASH_MODE")
	)
	(via
		(at 315.565282 -45.176948)
		(size 0.762)
		(drill 0.381)
		(layers "F.Cu" "B.Cu")
		(net "FM_ESPI_FLASH_MODE")
	)
	(segment
		(start 329.980036 -39.992046)
		(end 329.441048 -39.992046)
		(width 0.12954)
		(layer "F.Cu")
		(net "FM_ESPI_CS_SWIZZLE")
	)
	(via
		(at 328.866754 -33.998408)
		(size 0.6604)
		(drill 0.3302)
		(layers "F.Cu" "B.Cu")
		(net "FM_ESPI_CS_SWIZZLE")
	)
	(via
		(at 329.441048 -39.992046)
		(size 0.4572)
		(drill 0.2032)
		(layers "F.Cu" "B.Cu")
		(net "FM_ESPI_CS_SWIZZLE")
	)
	(segment
		(start 328.820526 -37.860986)
		(end 328.526648 -37.567108)
		(width 0.12954)
		(layer "B.Cu")
		(net "FM_ESPI_CS_SWIZZLE")
	)
	(segment
		(start 328.092816 -29.252926)
		(end 329.134724 -29.252926)
		(width 0.12954)
		(layer "B.Cu")
		(net "FM_ESPI_CS_SWIZZLE")
	)
	(segment
		(start 329.106022 -39.266876)
		(end 328.820526 -38.98138)
		(width 0.12954)
		(layer "B.Cu")
		(net "FM_ESPI_CS_SWIZZLE")
	)
	(segment
		(start 328.526648 -37.567108)
		(end 328.526648 -36.91128)
		(width 0.12954)
		(layer "B.Cu")
		(net "FM_ESPI_CS_SWIZZLE")
	)
	(segment
		(start 328.724514 -36.148518)
		(end 328.436986 -35.86099)
		(width 0.12954)
		(layer "B.Cu")
		(net "FM_ESPI_CS_SWIZZLE")
	)
	(segment
		(start 328.866754 -33.998408)
		(end 328.866754 -29.881068)
		(width 0.12954)
		(layer "B.Cu")
		(net "FM_ESPI_CS_SWIZZLE")
	)
	(segment
		(start 328.526648 -36.91128)
		(end 328.724514 -36.433506)
		(width 0.12954)
		(layer "B.Cu")
		(net "FM_ESPI_CS_SWIZZLE")
	)
	(segment
		(start 329.441048 -39.992046)
		(end 329.106022 -39.65702)
		(width 0.12954)
		(layer "B.Cu")
		(net "FM_ESPI_CS_SWIZZLE")
	)
	(segment
		(start 329.106022 -39.65702)
		(end 329.106022 -39.266876)
		(width 0.12954)
		(layer "B.Cu")
		(net "FM_ESPI_CS_SWIZZLE")
	)
	(segment
		(start 328.436986 -35.41522)
		(end 328.866754 -34.985452)
		(width 0.12954)
		(layer "B.Cu")
		(net "FM_ESPI_CS_SWIZZLE")
	)
	(segment
		(start 328.866754 -29.881068)
		(end 329.134978 -29.612844)
		(width 0.12954)
		(layer "B.Cu")
		(net "FM_ESPI_CS_SWIZZLE")
	)
	(segment
		(start 328.866754 -34.985452)
		(end 328.866754 -33.998408)
		(width 0.12954)
		(layer "B.Cu")
		(net "FM_ESPI_CS_SWIZZLE")
	)
	(segment
		(start 328.820526 -38.98138)
		(end 328.820526 -37.860986)
		(width 0.12954)
		(layer "B.Cu")
		(net "FM_ESPI_CS_SWIZZLE")
	)
	(segment
		(start 328.724514 -36.433506)
		(end 328.724514 -36.148518)
		(width 0.12954)
		(layer "B.Cu")
		(net "FM_ESPI_CS_SWIZZLE")
	)
	(segment
		(start 328.436986 -35.86099)
		(end 328.436986 -35.41522)
		(width 0.12954)
		(layer "B.Cu")
		(net "FM_ESPI_CS_SWIZZLE")
	)
	(segment
		(start 329.134724 -29.252926)
		(end 329.134978 -29.252672)
		(width 0.12954)
		(layer "B.Cu")
		(net "FM_ESPI_CS_SWIZZLE")
	)
	(segment
		(start 329.134978 -29.612844)
		(end 329.134978 -29.252672)
		(width 0.12954)
		(layer "B.Cu")
		(net "FM_ESPI_CS_SWIZZLE")
	)
	(segment
		(start 190.52032 -109.400848)
		(end 186.530234 -109.400848)
		(width 0.12954)
		(layer "F.Cu")
		(net "FM_DIS_PS_PWROK_DLY")
	)
	(segment
		(start 193.20383 -107.495848)
		(end 192.53454 -107.495848)
		(width 0.12954)
		(layer "F.Cu")
		(net "FM_DIS_PS_PWROK_DLY")
	)
	(segment
		(start 192.53454 -107.495848)
		(end 190.62954 -109.400848)
		(width 0.12954)
		(layer "F.Cu")
		(net "FM_DIS_PS_PWROK_DLY")
	)
	(segment
		(start 186.530234 -109.400848)
		(end 186.155584 -109.775498)
		(width 0.12954)
		(layer "F.Cu")
		(net "FM_DIS_PS_PWROK_DLY")
	)
	(segment
		(start 190.62954 -109.400848)
		(end 190.52032 -109.400848)
		(width 0.12954)
		(layer "F.Cu")
		(net "FM_DIS_PS_PWROK_DLY")
	)
	(segment
		(start 193.20383 -106.225848)
		(end 193.20383 -107.495848)
		(width 0.12954)
		(layer "F.Cu")
		(net "FM_DIS_PS_PWROK_DLY")
	)
	(via
		(at 190.52032 -109.400848)
		(size 0.762)
		(drill 0.381)
		(layers "F.Cu" "B.Cu")
		(net "FM_DIS_PS_PWROK_DLY")
	)
	(segment
		(start 184.555638 -116.175536)
		(end 184.955688 -116.575586)
		(width 0.12954)
		(layer "F.Cu")
		(net "FM_DIMM_12V_CPS_SX_N")
	)
	(segment
		(start 200.60031 -120.614948)
		(end 200.60031 -119.344948)
		(width 0.12954)
		(layer "F.Cu")
		(net "FM_DIMM_12V_CPS_SX_N")
	)
	(segment
		(start 200.60031 -119.344948)
		(end 199.98944 -119.344948)
		(width 0.12954)
		(layer "F.Cu")
		(net "FM_DIMM_12V_CPS_SX_N")
	)
	(via
		(at 199.98944 -119.344948)
		(size 0.508)
		(drill 0.254)
		(layers "F.Cu" "B.Cu")
		(net "FM_DIMM_12V_CPS_SX_N")
	)
	(via
		(at 184.955688 -116.575586)
		(size 0.4572)
		(drill 0.254)
		(layers "F.Cu" "B.Cu")
		(net "FM_DIMM_12V_CPS_SX_N")
	)
	(segment
		(start 197.862444 -119.82704)
		(end 193.82994 -119.82704)
		(width 0.127)
		(layer "In6.Cu")
		(net "FM_DIMM_12V_CPS_SX_N")
	)
	(segment
		(start 190.817246 -116.814346)
		(end 187.973208 -116.814346)
		(width 0.127)
		(layer "In6.Cu")
		(net "FM_DIMM_12V_CPS_SX_N")
	)
	(segment
		(start 198.037704 -119.65178)
		(end 197.862444 -119.82704)
		(width 0.127)
		(layer "In6.Cu")
		(net "FM_DIMM_12V_CPS_SX_N")
	)
	(segment
		(start 187.973208 -116.814346)
		(end 187.810394 -116.97716)
		(width 0.127)
		(layer "In6.Cu")
		(net "FM_DIMM_12V_CPS_SX_N")
	)
	(segment
		(start 187.810394 -116.97716)
		(end 185.4327 -116.97716)
		(width 0.127)
		(layer "In6.Cu")
		(net "FM_DIMM_12V_CPS_SX_N")
	)
	(segment
		(start 185.031126 -116.575586)
		(end 184.955688 -116.575586)
		(width 0.127)
		(layer "In6.Cu")
		(net "FM_DIMM_12V_CPS_SX_N")
	)
	(segment
		(start 185.4327 -116.97716)
		(end 185.031126 -116.575586)
		(width 0.127)
		(layer "In6.Cu")
		(net "FM_DIMM_12V_CPS_SX_N")
	)
	(segment
		(start 193.82994 -119.82704)
		(end 190.817246 -116.814346)
		(width 0.127)
		(layer "In6.Cu")
		(net "FM_DIMM_12V_CPS_SX_N")
	)
	(segment
		(start 199.98944 -119.344948)
		(end 199.682608 -119.65178)
		(width 0.127)
		(layer "In6.Cu")
		(net "FM_DIMM_12V_CPS_SX_N")
	)
	(segment
		(start 199.682608 -119.65178)
		(end 198.037704 -119.65178)
		(width 0.127)
		(layer "In6.Cu")
		(net "FM_DIMM_12V_CPS_SX_N")
	)
	(segment
		(start 343.81948 -40.461946)
		(end 343.5477 -39.992046)
		(width 0.12954)
		(layer "F.Cu")
		(net "FM_DEBUG_PORT_PRSNT_R_N")
	)
	(via
		(at 346.670376 -33.980628)
		(size 0.6604)
		(drill 0.3302)
		(layers "F.Cu" "B.Cu")
		(net "FM_DEBUG_PORT_PRSNT_R_N")
	)
	(via
		(at 343.5477 -39.992046)
		(size 0.4572)
		(drill 0.2032)
		(layers "F.Cu" "B.Cu")
		(net "FM_DEBUG_PORT_PRSNT_R_N")
	)
	(segment
		(start 346.897198 -32.58439)
		(end 346.897198 -31.527242)
		(width 0.12954)
		(layer "B.Cu")
		(net "FM_DEBUG_PORT_PRSNT_R_N")
	)
	(segment
		(start 346.670376 -32.811212)
		(end 346.897198 -32.58439)
		(width 0.12954)
		(layer "B.Cu")
		(net "FM_DEBUG_PORT_PRSNT_R_N")
	)
	(segment
		(start 346.670376 -38.191948)
		(end 346.670376 -33.980628)
		(width 0.12954)
		(layer "B.Cu")
		(net "FM_DEBUG_PORT_PRSNT_R_N")
	)
	(segment
		(start 346.670376 -33.980628)
		(end 346.670376 -32.811212)
		(width 0.12954)
		(layer "B.Cu")
		(net "FM_DEBUG_PORT_PRSNT_R_N")
	)
	(segment
		(start 344.870278 -39.992046)
		(end 346.670376 -38.191948)
		(width 0.12954)
		(layer "B.Cu")
		(net "FM_DEBUG_PORT_PRSNT_R_N")
	)
	(segment
		(start 343.5477 -39.992046)
		(end 344.870278 -39.992046)
		(width 0.12954)
		(layer "B.Cu")
		(net "FM_DEBUG_PORT_PRSNT_R_N")
	)
	(segment
		(start 216.05494 -112.865408)
		(end 216.05494 -112.92586)
		(width 0.12954)
		(layer "F.Cu")
		(net "FM_DEBUG_PORT_PRSNT_N")
	)
	(segment
		(start 205.377034 -111.219488)
		(end 198.77024 -111.219488)
		(width 0.12954)
		(layer "F.Cu")
		(net "FM_DEBUG_PORT_PRSNT_N")
	)
	(segment
		(start 214.3252 -114.6556)
		(end 214.122 -114.6556)
		(width 0.12954)
		(layer "F.Cu")
		(net "FM_DEBUG_PORT_PRSNT_N")
	)
	(segment
		(start 187.524136 -111.375444)
		(end 186.955684 -111.375444)
		(width 0.12954)
		(layer "F.Cu")
		(net "FM_DEBUG_PORT_PRSNT_N")
	)
	(segment
		(start 206.7814 -115.189)
		(end 206.7814 -112.623854)
		(width 0.12954)
		(layer "F.Cu")
		(net "FM_DEBUG_PORT_PRSNT_N")
	)
	(segment
		(start 195.780406 -110.651798)
		(end 192.875916 -110.651798)
		(width 0.12954)
		(layer "F.Cu")
		(net "FM_DEBUG_PORT_PRSNT_N")
	)
	(segment
		(start 192.875916 -110.651798)
		(end 191.660526 -111.867188)
		(width 0.12954)
		(layer "F.Cu")
		(net "FM_DEBUG_PORT_PRSNT_N")
	)
	(segment
		(start 196.109336 -110.322868)
		(end 195.780406 -110.651798)
		(width 0.12954)
		(layer "F.Cu")
		(net "FM_DEBUG_PORT_PRSNT_N")
	)
	(segment
		(start 206.7814 -112.623854)
		(end 205.377034 -111.219488)
		(width 0.12954)
		(layer "F.Cu")
		(net "FM_DEBUG_PORT_PRSNT_N")
	)
	(segment
		(start 207.4672 -115.8748)
		(end 206.7814 -115.189)
		(width 0.12954)
		(layer "F.Cu")
		(net "FM_DEBUG_PORT_PRSNT_N")
	)
	(segment
		(start 198.39432 -110.843568)
		(end 197.85076 -110.843568)
		(width 0.12954)
		(layer "F.Cu")
		(net "FM_DEBUG_PORT_PRSNT_N")
	)
	(segment
		(start 191.660526 -111.867188)
		(end 188.01588 -111.867188)
		(width 0.12954)
		(layer "F.Cu")
		(net "FM_DEBUG_PORT_PRSNT_N")
	)
	(segment
		(start 209.7278 -115.8748)
		(end 207.4672 -115.8748)
		(width 0.12954)
		(layer "F.Cu")
		(net "FM_DEBUG_PORT_PRSNT_N")
	)
	(segment
		(start 197.85076 -110.843568)
		(end 197.33006 -110.322868)
		(width 0.12954)
		(layer "F.Cu")
		(net "FM_DEBUG_PORT_PRSNT_N")
	)
	(segment
		(start 216.05494 -112.92586)
		(end 214.3252 -114.6556)
		(width 0.12954)
		(layer "F.Cu")
		(net "FM_DEBUG_PORT_PRSNT_N")
	)
	(segment
		(start 188.01588 -111.867188)
		(end 187.524136 -111.375444)
		(width 0.12954)
		(layer "F.Cu")
		(net "FM_DEBUG_PORT_PRSNT_N")
	)
	(segment
		(start 213.36 -115.4176)
		(end 210.185 -115.4176)
		(width 0.12954)
		(layer "F.Cu")
		(net "FM_DEBUG_PORT_PRSNT_N")
	)
	(segment
		(start 210.185 -115.4176)
		(end 209.7278 -115.8748)
		(width 0.12954)
		(layer "F.Cu")
		(net "FM_DEBUG_PORT_PRSNT_N")
	)
	(segment
		(start 214.122 -114.6556)
		(end 213.36 -115.4176)
		(width 0.12954)
		(layer "F.Cu")
		(net "FM_DEBUG_PORT_PRSNT_N")
	)
	(segment
		(start 197.33006 -110.322868)
		(end 196.109336 -110.322868)
		(width 0.12954)
		(layer "F.Cu")
		(net "FM_DEBUG_PORT_PRSNT_N")
	)
	(segment
		(start 198.77024 -111.219488)
		(end 198.39432 -110.843568)
		(width 0.12954)
		(layer "F.Cu")
		(net "FM_DEBUG_PORT_PRSNT_N")
	)
	(via
		(at 303.397412 -14.474444)
		(size 0.508)
		(drill 0.254)
		(layers "F.Cu" "B.Cu")
		(net "FM_DEBUG_PORT_PRSNT_N")
	)
	(via
		(at 274.362672 -23.043134)
		(size 0.508)
		(drill 0.254)
		(layers "F.Cu" "B.Cu")
		(net "FM_DEBUG_PORT_PRSNT_N")
	)
	(via
		(at 216.05494 -112.865408)
		(size 0.508)
		(drill 0.254)
		(layers "F.Cu" "B.Cu")
		(net "FM_DEBUG_PORT_PRSNT_N")
	)
	(via
		(at 286.360108 -115.868196)
		(size 0.508)
		(drill 0.254)
		(layers "F.Cu" "B.Cu")
		(net "FM_DEBUG_PORT_PRSNT_N")
	)
	(via
		(at 350.225106 -22.257004)
		(size 0.508)
		(drill 0.254)
		(layers "F.Cu" "B.Cu")
		(net "FM_DEBUG_PORT_PRSNT_N")
	)
	(segment
		(start 346.097098 -29.69133)
		(end 346.097098 -31.527242)
		(width 0.12954)
		(layer "B.Cu")
		(net "FM_DEBUG_PORT_PRSNT_N")
	)
	(segment
		(start 347.75902 -22.257004)
		(end 347.62948 -22.386544)
		(width 0.12954)
		(layer "B.Cu")
		(net "FM_DEBUG_PORT_PRSNT_N")
	)
	(segment
		(start 347.62948 -22.386544)
		(end 347.62948 -28.158948)
		(width 0.12954)
		(layer "B.Cu")
		(net "FM_DEBUG_PORT_PRSNT_N")
	)
	(segment
		(start 347.62948 -28.158948)
		(end 346.097098 -29.69133)
		(width 0.12954)
		(layer "B.Cu")
		(net "FM_DEBUG_PORT_PRSNT_N")
	)
	(segment
		(start 350.225106 -22.257004)
		(end 347.75902 -22.257004)
		(width 0.12954)
		(layer "B.Cu")
		(net "FM_DEBUG_PORT_PRSNT_N")
	)
	(segment
		(start 274.362672 -30.73273)
		(end 274.362672 -23.043134)
		(width 0.127)
		(layer "In2.Cu")
		(net "FM_DEBUG_PORT_PRSNT_N")
	)
	(segment
		(start 328.98461 -19.79168)
		(end 311.336436 -19.79168)
		(width 0.127)
		(layer "In2.Cu")
		(net "FM_DEBUG_PORT_PRSNT_N")
	)
	(segment
		(start 350.225106 -22.084538)
		(end 346.212922 -18.072354)
		(width 0.127)
		(layer "In2.Cu")
		(net "FM_DEBUG_PORT_PRSNT_N")
	)
	(segment
		(start 286.478472 -54.42585)
		(end 272.415 -40.362378)
		(width 0.127)
		(layer "In2.Cu")
		(net "FM_DEBUG_PORT_PRSNT_N")
	)
	(segment
		(start 286.360108 -106.746294)
		(end 286.478472 -106.62793)
		(width 0.127)
		(layer "In2.Cu")
		(net "FM_DEBUG_PORT_PRSNT_N")
	)
	(segment
		(start 286.360108 -115.868196)
		(end 286.360108 -106.746294)
		(width 0.127)
		(layer "In2.Cu")
		(net "FM_DEBUG_PORT_PRSNT_N")
	)
	(segment
		(start 272.415 -32.680402)
		(end 274.362672 -30.73273)
		(width 0.127)
		(layer "In2.Cu")
		(net "FM_DEBUG_PORT_PRSNT_N")
	)
	(segment
		(start 311.336436 -19.79168)
		(end 305.523392 -13.978636)
		(width 0.127)
		(layer "In2.Cu")
		(net "FM_DEBUG_PORT_PRSNT_N")
	)
	(segment
		(start 341.544656 -18.072354)
		(end 337.552792 -22.064218)
		(width 0.127)
		(layer "In2.Cu")
		(net "FM_DEBUG_PORT_PRSNT_N")
	)
	(segment
		(start 305.523392 -13.978636)
		(end 303.89322 -13.978636)
		(width 0.127)
		(layer "In2.Cu")
		(net "FM_DEBUG_PORT_PRSNT_N")
	)
	(segment
		(start 337.552792 -22.064218)
		(end 331.257148 -22.064218)
		(width 0.127)
		(layer "In2.Cu")
		(net "FM_DEBUG_PORT_PRSNT_N")
	)
	(segment
		(start 350.225106 -22.257004)
		(end 350.225106 -22.084538)
		(width 0.127)
		(layer "In2.Cu")
		(net "FM_DEBUG_PORT_PRSNT_N")
	)
	(segment
		(start 346.212922 -18.072354)
		(end 341.544656 -18.072354)
		(width 0.127)
		(layer "In2.Cu")
		(net "FM_DEBUG_PORT_PRSNT_N")
	)
	(segment
		(start 331.257148 -22.064218)
		(end 328.98461 -19.79168)
		(width 0.127)
		(layer "In2.Cu")
		(net "FM_DEBUG_PORT_PRSNT_N")
	)
	(segment
		(start 286.478472 -106.62793)
		(end 286.478472 -54.42585)
		(width 0.127)
		(layer "In2.Cu")
		(net "FM_DEBUG_PORT_PRSNT_N")
	)
	(segment
		(start 303.89322 -13.978636)
		(end 303.397412 -14.474444)
		(width 0.127)
		(layer "In2.Cu")
		(net "FM_DEBUG_PORT_PRSNT_N")
	)
	(segment
		(start 272.415 -40.362378)
		(end 272.415 -32.680402)
		(width 0.127)
		(layer "In2.Cu")
		(net "FM_DEBUG_PORT_PRSNT_N")
	)
	(segment
		(start 296.250106 -18.104104)
		(end 297.390058 -16.964152)
		(width 0.127)
		(layer "In4.Cu")
		(net "FM_DEBUG_PORT_PRSNT_N")
	)
	(segment
		(start 303.397412 -14.938756)
		(end 303.397412 -14.474444)
		(width 0.127)
		(layer "In4.Cu")
		(net "FM_DEBUG_PORT_PRSNT_N")
	)
	(segment
		(start 297.390058 -16.964152)
		(end 301.372016 -16.964152)
		(width 0.127)
		(layer "In4.Cu")
		(net "FM_DEBUG_PORT_PRSNT_N")
	)
	(segment
		(start 280.129742 -21.562314)
		(end 287.901126 -21.562314)
		(width 0.127)
		(layer "In4.Cu")
		(net "FM_DEBUG_PORT_PRSNT_N")
	)
	(segment
		(start 287.901126 -21.562314)
		(end 296.250106 -18.104104)
		(width 0.127)
		(layer "In4.Cu")
		(net "FM_DEBUG_PORT_PRSNT_N")
	)
	(segment
		(start 274.362672 -23.043134)
		(end 278.648922 -23.043134)
		(width 0.127)
		(layer "In4.Cu")
		(net "FM_DEBUG_PORT_PRSNT_N")
	)
	(segment
		(start 278.648922 -23.043134)
		(end 280.129742 -21.562314)
		(width 0.127)
		(layer "In4.Cu")
		(net "FM_DEBUG_PORT_PRSNT_N")
	)
	(segment
		(start 301.372016 -16.964152)
		(end 303.397412 -14.938756)
		(width 0.127)
		(layer "In4.Cu")
		(net "FM_DEBUG_PORT_PRSNT_N")
	)
	(segment
		(start 286.360108 -115.868196)
		(end 285.81096 -116.417344)
		(width 0.127)
		(layer "In6.Cu")
		(net "FM_DEBUG_PORT_PRSNT_N")
	)
	(segment
		(start 240.23701 -113.440464)
		(end 237.561374 -113.440464)
		(width 0.127)
		(layer "In6.Cu")
		(net "FM_DEBUG_PORT_PRSNT_N")
	)
	(segment
		(start 217.185748 -113.111026)
		(end 216.300558 -113.111026)
		(width 0.127)
		(layer "In6.Cu")
		(net "FM_DEBUG_PORT_PRSNT_N")
	)
	(segment
		(start 285.81096 -116.417344)
		(end 243.21389 -116.417344)
		(width 0.127)
		(layer "In6.Cu")
		(net "FM_DEBUG_PORT_PRSNT_N")
	)
	(segment
		(start 236.348778 -112.227868)
		(end 223.927416 -112.227868)
		(width 0.127)
		(layer "In6.Cu")
		(net "FM_DEBUG_PORT_PRSNT_N")
	)
	(segment
		(start 222.236792 -113.918492)
		(end 217.993214 -113.918492)
		(width 0.127)
		(layer "In6.Cu")
		(net "FM_DEBUG_PORT_PRSNT_N")
	)
	(segment
		(start 217.993214 -113.918492)
		(end 217.185748 -113.111026)
		(width 0.127)
		(layer "In6.Cu")
		(net "FM_DEBUG_PORT_PRSNT_N")
	)
	(segment
		(start 223.927416 -112.227868)
		(end 222.236792 -113.918492)
		(width 0.127)
		(layer "In6.Cu")
		(net "FM_DEBUG_PORT_PRSNT_N")
	)
	(segment
		(start 216.300558 -113.111026)
		(end 216.05494 -112.865408)
		(width 0.127)
		(layer "In6.Cu")
		(net "FM_DEBUG_PORT_PRSNT_N")
	)
	(segment
		(start 243.21389 -116.417344)
		(end 240.23701 -113.440464)
		(width 0.127)
		(layer "In6.Cu")
		(net "FM_DEBUG_PORT_PRSNT_N")
	)
	(segment
		(start 237.561374 -113.440464)
		(end 236.348778 -112.227868)
		(width 0.127)
		(layer "In6.Cu")
		(net "FM_DEBUG_PORT_PRSNT_N")
	)
	(segment
		(start 236.87659 -125.77445)
		(end 237.119922 -126.017782)
		(width 0.12954)
		(layer "F.Cu")
		(net "FM_DB2000_VSBEN")
	)
	(segment
		(start 237.119922 -126.017782)
		(end 237.247938 -126.017782)
		(width 0.12954)
		(layer "F.Cu")
		(net "FM_DB2000_VSBEN")
	)
	(segment
		(start 236.822742 -125.77445)
		(end 236.87659 -125.77445)
		(width 0.12954)
		(layer "F.Cu")
		(net "FM_DB2000_VSBEN")
	)
	(via
		(at 236.822742 -125.77445)
		(size 0.49022)
		(drill 0.254)
		(layers "F.Cu" "B.Cu")
		(net "FM_DB2000_VSBEN")
	)
	(via
		(at 237.998 -124.251466)
		(size 0.6604)
		(drill 0.3302)
		(layers "F.Cu" "B.Cu")
		(net "FM_DB2000_VSBEN")
	)
	(segment
		(start 273.252692 -97.063814)
		(end 272.48612 -97.063814)
		(width 0.12954)
		(layer "F.Cu")
		(net "FM_DB2000_OE_N")
	)
	(segment
		(start 224.76714 -113.538508)
		(end 227.007928 -111.29772)
		(width 0.12954)
		(layer "F.Cu")
		(net "FM_DB2000_OE_N")
	)
	(segment
		(start 218.585796 -113.886488)
		(end 219.447618 -114.74831)
		(width 0.12954)
		(layer "F.Cu")
		(net "FM_DB2000_OE_N")
	)
	(segment
		(start 227.007928 -111.29772)
		(end 237.151672 -111.29772)
		(width 0.12954)
		(layer "F.Cu")
		(net "FM_DB2000_OE_N")
	)
	(segment
		(start 238.162592 -112.30864)
		(end 263.565894 -112.30864)
		(width 0.12954)
		(layer "F.Cu")
		(net "FM_DB2000_OE_N")
	)
	(segment
		(start 218.585796 -113.132616)
		(end 218.585796 -113.886488)
		(width 0.12954)
		(layer "F.Cu")
		(net "FM_DB2000_OE_N")
	)
	(segment
		(start 273.705828 -99.304348)
		(end 273.705828 -97.51695)
		(width 0.12954)
		(layer "F.Cu")
		(net "FM_DB2000_OE_N")
	)
	(segment
		(start 222.70339 -113.538508)
		(end 224.76714 -113.538508)
		(width 0.12954)
		(layer "F.Cu")
		(net "FM_DB2000_OE_N")
	)
	(segment
		(start 219.447618 -114.74831)
		(end 221.493588 -114.74831)
		(width 0.12954)
		(layer "F.Cu")
		(net "FM_DB2000_OE_N")
	)
	(segment
		(start 221.493588 -114.74831)
		(end 222.70339 -113.538508)
		(width 0.12954)
		(layer "F.Cu")
		(net "FM_DB2000_OE_N")
	)
	(segment
		(start 273.705828 -102.168706)
		(end 273.705828 -99.304348)
		(width 0.12954)
		(layer "F.Cu")
		(net "FM_DB2000_OE_N")
	)
	(segment
		(start 273.705828 -97.51695)
		(end 273.252692 -97.063814)
		(width 0.12954)
		(layer "F.Cu")
		(net "FM_DB2000_OE_N")
	)
	(segment
		(start 237.151672 -111.29772)
		(end 238.162592 -112.30864)
		(width 0.12954)
		(layer "F.Cu")
		(net "FM_DB2000_OE_N")
	)
	(segment
		(start 263.565894 -112.30864)
		(end 273.705828 -102.168706)
		(width 0.12954)
		(layer "F.Cu")
		(net "FM_DB2000_OE_N")
	)
	(via
		(at 218.585796 -113.132616)
		(size 0.508)
		(drill 0.254)
		(layers "F.Cu" "B.Cu")
		(net "FM_DB2000_OE_N")
	)
	(via
		(at 273.705828 -99.304348)
		(size 0.762)
		(drill 0.381)
		(layers "F.Cu" "B.Cu")
		(net "FM_DB2000_OE_N")
	)
	(segment
		(start 222.047562 -129.445258)
		(end 222.767906 -130.165602)
		(width 0.12954)
		(layer "B.Cu")
		(net "FM_DB2000_OE_N")
	)
	(segment
		(start 218.585796 -113.132616)
		(end 218.585796 -114.489484)
		(width 0.12954)
		(layer "B.Cu")
		(net "FM_DB2000_OE_N")
	)
	(segment
		(start 217.83167 -120.908318)
		(end 222.047562 -125.12421)
		(width 0.12954)
		(layer "B.Cu")
		(net "FM_DB2000_OE_N")
	)
	(segment
		(start 228.657658 -129.028952)
		(end 229.199186 -129.028952)
		(width 0.12954)
		(layer "B.Cu")
		(net "FM_DB2000_OE_N")
	)
	(segment
		(start 225.967036 -130.165602)
		(end 226.531932 -129.600706)
		(width 0.12954)
		(layer "B.Cu")
		(net "FM_DB2000_OE_N")
	)
	(segment
		(start 229.199186 -129.028952)
		(end 229.361746 -128.866392)
		(width 0.12954)
		(layer "B.Cu")
		(net "FM_DB2000_OE_N")
	)
	(segment
		(start 228.085904 -129.600706)
		(end 228.657658 -129.028952)
		(width 0.12954)
		(layer "B.Cu")
		(net "FM_DB2000_OE_N")
	)
	(segment
		(start 222.767906 -130.165602)
		(end 225.967036 -130.165602)
		(width 0.12954)
		(layer "B.Cu")
		(net "FM_DB2000_OE_N")
	)
	(segment
		(start 218.585796 -114.489484)
		(end 217.83167 -115.24361)
		(width 0.12954)
		(layer "B.Cu")
		(net "FM_DB2000_OE_N")
	)
	(segment
		(start 217.83167 -115.24361)
		(end 217.83167 -120.908318)
		(width 0.12954)
		(layer "B.Cu")
		(net "FM_DB2000_OE_N")
	)
	(segment
		(start 226.531932 -129.600706)
		(end 228.085904 -129.600706)
		(width 0.12954)
		(layer "B.Cu")
		(net "FM_DB2000_OE_N")
	)
	(segment
		(start 222.047562 -125.12421)
		(end 222.047562 -129.445258)
		(width 0.12954)
		(layer "B.Cu")
		(net "FM_DB2000_OE_N")
	)
	(segment
		(start 235.247942 -130.147314)
		(end 235.247942 -129.517902)
		(width 0.12954)
		(layer "F.Cu")
		(net "FM_DB2000_DEV_EN")
	)
	(via
		(at 235.247942 -130.147314)
		(size 0.49022)
		(drill 0.254)
		(layers "F.Cu" "B.Cu")
		(net "FM_DB2000_DEV_EN")
	)
	(segment
		(start 235.247942 -130.147314)
		(end 235.247942 -130.584194)
		(width 0.12954)
		(layer "B.Cu")
		(net "FM_DB2000_DEV_EN")
	)
	(segment
		(start 235.247942 -130.584194)
		(end 234.889294 -130.942842)
		(width 0.12954)
		(layer "B.Cu")
		(net "FM_DB2000_DEV_EN")
	)
	(segment
		(start 234.889294 -130.942842)
		(end 234.889294 -132.070856)
		(width 0.12954)
		(layer "B.Cu")
		(net "FM_DB2000_DEV_EN")
	)
	(segment
		(start 231.135936 -126.06782)
		(end 231.185974 -126.017782)
		(width 0.12954)
		(layer "F.Cu")
		(net "FM_DB2000_9_OE_N")
	)
	(segment
		(start 231.185974 -126.017782)
		(end 232.247948 -126.017782)
		(width 0.12954)
		(layer "F.Cu")
		(net "FM_DB2000_9_OE_N")
	)
	(via
		(at 231.858312 -126.555754)
		(size 0.7112)
		(drill 0.3556)
		(layers "F.Cu" "B.Cu")
		(net "FM_DB2000_9_OE_N")
	)
	(via
		(at 231.135936 -126.06782)
		(size 0.49022)
		(drill 0.254)
		(layers "F.Cu" "B.Cu")
		(net "FM_DB2000_9_OE_N")
	)
	(segment
		(start 231.62387 -126.555754)
		(end 231.135936 -126.06782)
		(width 0.12954)
		(layer "B.Cu")
		(net "FM_DB2000_9_OE_N")
	)
	(segment
		(start 231.688386 -125.941328)
		(end 231.688386 -125.377194)
		(width 0.12954)
		(layer "B.Cu")
		(net "FM_DB2000_9_OE_N")
	)
	(segment
		(start 231.858312 -126.555754)
		(end 231.858312 -126.111254)
		(width 0.12954)
		(layer "B.Cu")
		(net "FM_DB2000_9_OE_N")
	)
	(segment
		(start 231.858312 -126.111254)
		(end 231.688386 -125.941328)
		(width 0.12954)
		(layer "B.Cu")
		(net "FM_DB2000_9_OE_N")
	)
	(segment
		(start 231.858312 -126.555754)
		(end 231.62387 -126.555754)
		(width 0.12954)
		(layer "B.Cu")
		(net "FM_DB2000_9_OE_N")
	)
	(segment
		(start 233.068622 -127.197358)
		(end 232.748074 -127.517906)
		(width 0.12954)
		(layer "F.Cu")
		(net "FM_DB2000_8_OE_N")
	)
	(segment
		(start 233.225848 -127.197358)
		(end 233.068622 -127.197358)
		(width 0.12954)
		(layer "F.Cu")
		(net "FM_DB2000_8_OE_N")
	)
	(via
		(at 233.225848 -127.197358)
		(size 0.49022)
		(drill 0.254)
		(layers "F.Cu" "B.Cu")
		(net "FM_DB2000_8_OE_N")
	)
	(segment
		(start 231.907842 -128.278128)
		(end 232.988612 -127.197358)
		(width 0.12954)
		(layer "B.Cu")
		(net "FM_DB2000_8_OE_N")
	)
	(segment
		(start 230.646224 -128.278128)
		(end 231.907842 -128.278128)
		(width 0.12954)
		(layer "B.Cu")
		(net "FM_DB2000_8_OE_N")
	)
	(segment
		(start 230.29037 -127.922274)
		(end 230.646224 -128.278128)
		(width 0.12954)
		(layer "B.Cu")
		(net "FM_DB2000_8_OE_N")
	)
	(segment
		(start 232.988612 -127.197358)
		(end 233.225848 -127.197358)
		(width 0.12954)
		(layer "B.Cu")
		(net "FM_DB2000_8_OE_N")
	)
	(segment
		(start 233.329226 -129.017776)
		(end 233.247946 -129.017776)
		(width 0.0889)
		(layer "F.Cu")
		(net "FM_DB2000_1_OE_N")
	)
	(segment
		(start 234.640628 -128.543304)
		(end 234.247436 -128.942338)
		(width 0.12954)
		(layer "F.Cu")
		(net "FM_DB2000_1_OE_N")
	)
	(segment
		(start 233.217974 -127.95504)
		(end 232.748074 -128.42494)
		(width 0.0889)
		(layer "F.Cu")
		(net "FM_DB2000_1_OE_N")
	)
	(segment
		(start 233.205274 -127.84582)
		(end 233.217974 -127.85852)
		(width 0.0889)
		(layer "F.Cu")
		(net "FM_DB2000_1_OE_N")
	)
	(segment
		(start 233.217974 -127.85852)
		(end 233.217974 -127.95504)
		(width 0.0889)
		(layer "F.Cu")
		(net "FM_DB2000_1_OE_N")
	)
	(segment
		(start 234.640882 -128.543304)
		(end 234.640628 -128.543304)
		(width 0.12954)
		(layer "F.Cu")
		(net "FM_DB2000_1_OE_N")
	)
	(segment
		(start 232.748074 -128.42494)
		(end 232.748074 -128.517904)
		(width 0.0889)
		(layer "F.Cu")
		(net "FM_DB2000_1_OE_N")
	)
	(segment
		(start 233.94924 -128.545844)
		(end 233.801158 -128.545844)
		(width 0.0889)
		(layer "F.Cu")
		(net "FM_DB2000_1_OE_N")
	)
	(segment
		(start 234.247436 -128.942338)
		(end 234.247944 -129.017776)
		(width 0.12954)
		(layer "F.Cu")
		(net "FM_DB2000_1_OE_N")
	)
	(segment
		(start 233.801158 -128.545844)
		(end 233.329226 -129.017776)
		(width 0.0889)
		(layer "F.Cu")
		(net "FM_DB2000_1_OE_N")
	)
	(via
		(at 234.640882 -128.543304)
		(size 0.49022)
		(drill 0.254)
		(layers "F.Cu" "B.Cu")
		(net "FM_DB2000_1_OE_N")
	)
	(via
		(at 233.94924 -128.545844)
		(size 0.49022)
		(drill 0.254)
		(layers "F.Cu" "B.Cu")
		(net "FM_DB2000_1_OE_N")
	)
	(via
		(at 233.205274 -127.84582)
		(size 0.49022)
		(drill 0.254)
		(layers "F.Cu" "B.Cu")
		(net "FM_DB2000_1_OE_N")
	)
	(via
		(at 231.485694 -129.083054)
		(size 0.6604)
		(drill 0.3302)
		(layers "F.Cu" "B.Cu")
		(net "FM_DB2000_1_OE_N")
	)
	(segment
		(start 231.839008 -129.083054)
		(end 233.076242 -127.84582)
		(width 0.12954)
		(layer "B.Cu")
		(net "FM_DB2000_1_OE_N")
	)
	(segment
		(start 231.485694 -129.083054)
		(end 231.839008 -129.083054)
		(width 0.12954)
		(layer "B.Cu")
		(net "FM_DB2000_1_OE_N")
	)
	(segment
		(start 230.161846 -128.866392)
		(end 230.378508 -129.083054)
		(width 0.12954)
		(layer "B.Cu")
		(net "FM_DB2000_1_OE_N")
	)
	(segment
		(start 230.378508 -129.083054)
		(end 231.485694 -129.083054)
		(width 0.12954)
		(layer "B.Cu")
		(net "FM_DB2000_1_OE_N")
	)
	(segment
		(start 233.076242 -127.84582)
		(end 233.205274 -127.84582)
		(width 0.12954)
		(layer "B.Cu")
		(net "FM_DB2000_1_OE_N")
	)
	(segment
		(start 233.14025 -126.409958)
		(end 232.748074 -126.017782)
		(width 0.12954)
		(layer "F.Cu")
		(net "FM_DB2000_10_OE_N")
	)
	(segment
		(start 233.225848 -126.409958)
		(end 233.14025 -126.409958)
		(width 0.12954)
		(layer "F.Cu")
		(net "FM_DB2000_10_OE_N")
	)
	(via
		(at 233.225848 -126.409958)
		(size 0.49022)
		(drill 0.254)
		(layers "F.Cu" "B.Cu")
		(net "FM_DB2000_10_OE_N")
	)
	(via
		(at 231.48036 -127.729488)
		(size 0.7112)
		(drill 0.3556)
		(layers "F.Cu" "B.Cu")
		(net "FM_DB2000_10_OE_N")
	)
	(segment
		(start 231.691942 -127.729488)
		(end 231.48036 -127.729488)
		(width 0.12954)
		(layer "B.Cu")
		(net "FM_DB2000_10_OE_N")
	)
	(segment
		(start 231.48036 -127.729488)
		(end 231.319832 -127.729488)
		(width 0.12954)
		(layer "B.Cu")
		(net "FM_DB2000_10_OE_N")
	)
	(segment
		(start 233.225848 -126.409958)
		(end 233.018838 -126.616968)
		(width 0.12954)
		(layer "B.Cu")
		(net "FM_DB2000_10_OE_N")
	)
	(segment
		(start 231.319832 -127.729488)
		(end 230.620062 -127.029718)
		(width 0.12954)
		(layer "B.Cu")
		(net "FM_DB2000_10_OE_N")
	)
	(segment
		(start 233.018838 -126.616968)
		(end 232.804462 -126.616968)
		(width 0.12954)
		(layer "B.Cu")
		(net "FM_DB2000_10_OE_N")
	)
	(segment
		(start 230.620062 -127.029718)
		(end 230.29037 -127.029718)
		(width 0.12954)
		(layer "B.Cu")
		(net "FM_DB2000_10_OE_N")
	)
	(segment
		(start 232.804462 -126.616968)
		(end 231.691942 -127.729488)
		(width 0.12954)
		(layer "B.Cu")
		(net "FM_DB2000_10_OE_N")
	)
	(segment
		(start 186.55538 -110.175548)
		(end 186.155584 -110.575344)
		(width 0.12954)
		(layer "F.Cu")
		(net "FM_CPU_RMCA_CATERR_LVT3_R_N")
	)
	(segment
		(start 192.7606 -108.765848)
		(end 191.80556 -109.720888)
		(width 0.12954)
		(layer "F.Cu")
		(net "FM_CPU_RMCA_CATERR_LVT3_R_N")
	)
	(segment
		(start 190.50508 -110.691168)
		(end 188.09208 -110.691168)
		(width 0.12954)
		(layer "F.Cu")
		(net "FM_CPU_RMCA_CATERR_LVT3_R_N")
	)
	(segment
		(start 187.57646 -110.175548)
		(end 186.55538 -110.175548)
		(width 0.12954)
		(layer "F.Cu")
		(net "FM_CPU_RMCA_CATERR_LVT3_R_N")
	)
	(segment
		(start 195.293742 -109.478318)
		(end 193.61023 -109.478318)
		(width 0.12954)
		(layer "F.Cu")
		(net "FM_CPU_RMCA_CATERR_LVT3_R_N")
	)
	(segment
		(start 188.09208 -110.691168)
		(end 187.57646 -110.175548)
		(width 0.12954)
		(layer "F.Cu")
		(net "FM_CPU_RMCA_CATERR_LVT3_R_N")
	)
	(segment
		(start 193.20383 -109.071918)
		(end 193.20383 -108.765848)
		(width 0.12954)
		(layer "F.Cu")
		(net "FM_CPU_RMCA_CATERR_LVT3_R_N")
	)
	(segment
		(start 195.683632 -109.088428)
		(end 195.293742 -109.478318)
		(width 0.12954)
		(layer "F.Cu")
		(net "FM_CPU_RMCA_CATERR_LVT3_R_N")
	)
	(segment
		(start 191.80556 -110.038388)
		(end 191.15278 -110.691168)
		(width 0.12954)
		(layer "F.Cu")
		(net "FM_CPU_RMCA_CATERR_LVT3_R_N")
	)
	(segment
		(start 199.3519 -109.296708)
		(end 199.14362 -109.088428)
		(width 0.12954)
		(layer "F.Cu")
		(net "FM_CPU_RMCA_CATERR_LVT3_R_N")
	)
	(segment
		(start 193.61023 -109.478318)
		(end 193.20383 -109.071918)
		(width 0.12954)
		(layer "F.Cu")
		(net "FM_CPU_RMCA_CATERR_LVT3_R_N")
	)
	(segment
		(start 191.15278 -110.691168)
		(end 190.50508 -110.691168)
		(width 0.12954)
		(layer "F.Cu")
		(net "FM_CPU_RMCA_CATERR_LVT3_R_N")
	)
	(segment
		(start 200.58888 -108.822998)
		(end 200.11517 -109.296708)
		(width 0.12954)
		(layer "F.Cu")
		(net "FM_CPU_RMCA_CATERR_LVT3_R_N")
	)
	(segment
		(start 200.11517 -109.296708)
		(end 199.3519 -109.296708)
		(width 0.12954)
		(layer "F.Cu")
		(net "FM_CPU_RMCA_CATERR_LVT3_R_N")
	)
	(segment
		(start 201.73188 -108.822998)
		(end 200.58888 -108.822998)
		(width 0.12954)
		(layer "F.Cu")
		(net "FM_CPU_RMCA_CATERR_LVT3_R_N")
	)
	(segment
		(start 193.20383 -108.765848)
		(end 192.7606 -108.765848)
		(width 0.12954)
		(layer "F.Cu")
		(net "FM_CPU_RMCA_CATERR_LVT3_R_N")
	)
	(segment
		(start 199.14362 -109.088428)
		(end 195.683632 -109.088428)
		(width 0.12954)
		(layer "F.Cu")
		(net "FM_CPU_RMCA_CATERR_LVT3_R_N")
	)
	(segment
		(start 191.80556 -109.720888)
		(end 191.80556 -110.038388)
		(width 0.12954)
		(layer "F.Cu")
		(net "FM_CPU_RMCA_CATERR_LVT3_R_N")
	)
	(via
		(at 190.50508 -110.691168)
		(size 0.762)
		(drill 0.381)
		(layers "F.Cu" "B.Cu")
		(net "FM_CPU_RMCA_CATERR_LVT3_R_N")
	)
	(segment
		(start 315.910722 -46.830488)
		(end 316.073282 -46.993048)
		(width 0.12954)
		(layer "F.Cu")
		(net "FM_CPU_RMCA_CATERR_DLY_N")
	)
	(segment
		(start 322.779898 -47.642272)
		(end 326.533002 -47.642272)
		(width 0.0889)
		(layer "F.Cu")
		(net "FM_CPU_RMCA_CATERR_DLY_N")
	)
	(segment
		(start 317.305182 -47.289974)
		(end 317.587376 -47.289974)
		(width 0.12954)
		(layer "F.Cu")
		(net "FM_CPU_RMCA_CATERR_DLY_N")
	)
	(segment
		(start 326.868028 -47.751746)
		(end 327.145396 -47.751746)
		(width 0.0889)
		(layer "F.Cu")
		(net "FM_CPU_RMCA_CATERR_DLY_N")
	)
	(segment
		(start 316.073282 -46.993048)
		(end 317.008256 -46.993048)
		(width 0.12954)
		(layer "F.Cu")
		(net "FM_CPU_RMCA_CATERR_DLY_N")
	)
	(segment
		(start 318.089534 -47.792132)
		(end 322.630038 -47.792132)
		(width 0.12954)
		(layer "F.Cu")
		(net "FM_CPU_RMCA_CATERR_DLY_N")
	)
	(segment
		(start 310.199532 -46.830488)
		(end 315.910722 -46.830488)
		(width 0.12954)
		(layer "F.Cu")
		(net "FM_CPU_RMCA_CATERR_DLY_N")
	)
	(segment
		(start 317.587376 -47.289974)
		(end 318.089534 -47.792132)
		(width 0.12954)
		(layer "F.Cu")
		(net "FM_CPU_RMCA_CATERR_DLY_N")
	)
	(segment
		(start 326.716644 -47.650908)
		(end 326.868028 -47.751746)
		(width 0.0889)
		(layer "F.Cu")
		(net "FM_CPU_RMCA_CATERR_DLY_N")
	)
	(segment
		(start 327.45553 -47.44974)
		(end 327.829926 -47.44974)
		(width 0.0889)
		(layer "F.Cu")
		(net "FM_CPU_RMCA_CATERR_DLY_N")
	)
	(segment
		(start 322.630038 -47.792132)
		(end 322.779898 -47.642272)
		(width 0.0889)
		(layer "F.Cu")
		(net "FM_CPU_RMCA_CATERR_DLY_N")
	)
	(segment
		(start 317.008256 -46.993048)
		(end 317.305182 -47.289974)
		(width 0.12954)
		(layer "F.Cu")
		(net "FM_CPU_RMCA_CATERR_DLY_N")
	)
	(segment
		(start 309.922672 -47.107348)
		(end 310.199532 -46.830488)
		(width 0.12954)
		(layer "F.Cu")
		(net "FM_CPU_RMCA_CATERR_DLY_N")
	)
	(segment
		(start 327.20534 -47.69993)
		(end 327.45553 -47.44974)
		(width 0.0889)
		(layer "F.Cu")
		(net "FM_CPU_RMCA_CATERR_DLY_N")
	)
	(segment
		(start 327.145396 -47.751746)
		(end 327.20534 -47.69993)
		(width 0.0889)
		(layer "F.Cu")
		(net "FM_CPU_RMCA_CATERR_DLY_N")
	)
	(segment
		(start 326.533002 -47.642272)
		(end 326.716644 -47.650908)
		(width 0.0889)
		(layer "F.Cu")
		(net "FM_CPU_RMCA_CATERR_DLY_N")
	)
	(via
		(at 317.008256 -46.993048)
		(size 0.762)
		(drill 0.381)
		(layers "F.Cu" "B.Cu")
		(net "FM_CPU_RMCA_CATERR_DLY_N")
	)
	(segment
		(start 180.555646 -116.975382)
		(end 180.955696 -117.375432)
		(width 0.12954)
		(layer "F.Cu")
		(net "FM_CPU_RMCA_CATERR_DLY_LVT3_R_N")
	)
	(segment
		(start 308.962552 -47.267368)
		(end 309.122572 -47.107348)
		(width 0.12954)
		(layer "F.Cu")
		(net "FM_CPU_RMCA_CATERR_DLY_LVT3_R_N")
	)
	(segment
		(start 308.369716 -47.267368)
		(end 308.962552 -47.267368)
		(width 0.12954)
		(layer "F.Cu")
		(net "FM_CPU_RMCA_CATERR_DLY_LVT3_R_N")
	)
	(via
		(at 180.955696 -117.375432)
		(size 0.4572)
		(drill 0.254)
		(layers "F.Cu" "B.Cu")
		(net "FM_CPU_RMCA_CATERR_DLY_LVT3_R_N")
	)
	(via
		(at 320.09588 -121.249948)
		(size 0.508)
		(drill 0.254)
		(layers "F.Cu" "B.Cu")
		(net "FM_CPU_RMCA_CATERR_DLY_LVT3_R_N")
	)
	(via
		(at 308.369716 -47.267368)
		(size 0.508)
		(drill 0.254)
		(layers "F.Cu" "B.Cu")
		(net "FM_CPU_RMCA_CATERR_DLY_LVT3_R_N")
	)
	(segment
		(start 321.7799 -112.011968)
		(end 321.7799 -82.40903)
		(width 0.127)
		(layer "In2.Cu")
		(net "FM_CPU_RMCA_CATERR_DLY_LVT3_R_N")
	)
	(segment
		(start 309.14848 -50.891948)
		(end 309.14848 -48.046132)
		(width 0.127)
		(layer "In2.Cu")
		(net "FM_CPU_RMCA_CATERR_DLY_LVT3_R_N")
	)
	(segment
		(start 316.133988 -76.763118)
		(end 311.8866 -66.509138)
		(width 0.127)
		(layer "In2.Cu")
		(net "FM_CPU_RMCA_CATERR_DLY_LVT3_R_N")
	)
	(segment
		(start 308.20868 -51.831748)
		(end 309.14848 -50.891948)
		(width 0.127)
		(layer "In2.Cu")
		(net "FM_CPU_RMCA_CATERR_DLY_LVT3_R_N")
	)
	(segment
		(start 320.09588 -121.249948)
		(end 322.38188 -118.963948)
		(width 0.127)
		(layer "In2.Cu")
		(net "FM_CPU_RMCA_CATERR_DLY_LVT3_R_N")
	)
	(segment
		(start 311.8866 -58.513472)
		(end 308.20868 -54.835552)
		(width 0.127)
		(layer "In2.Cu")
		(net "FM_CPU_RMCA_CATERR_DLY_LVT3_R_N")
	)
	(segment
		(start 322.38188 -112.613948)
		(end 321.7799 -112.011968)
		(width 0.127)
		(layer "In2.Cu")
		(net "FM_CPU_RMCA_CATERR_DLY_LVT3_R_N")
	)
	(segment
		(start 308.20868 -54.835552)
		(end 308.20868 -51.831748)
		(width 0.127)
		(layer "In2.Cu")
		(net "FM_CPU_RMCA_CATERR_DLY_LVT3_R_N")
	)
	(segment
		(start 311.8866 -66.509138)
		(end 311.8866 -58.513472)
		(width 0.127)
		(layer "In2.Cu")
		(net "FM_CPU_RMCA_CATERR_DLY_LVT3_R_N")
	)
	(segment
		(start 322.38188 -118.963948)
		(end 322.38188 -112.613948)
		(width 0.127)
		(layer "In2.Cu")
		(net "FM_CPU_RMCA_CATERR_DLY_LVT3_R_N")
	)
	(segment
		(start 321.7799 -82.40903)
		(end 316.133988 -76.763118)
		(width 0.127)
		(layer "In2.Cu")
		(net "FM_CPU_RMCA_CATERR_DLY_LVT3_R_N")
	)
	(segment
		(start 309.14848 -48.046132)
		(end 308.369716 -47.267368)
		(width 0.127)
		(layer "In2.Cu")
		(net "FM_CPU_RMCA_CATERR_DLY_LVT3_R_N")
	)
	(segment
		(start 232.541318 -122.113548)
		(end 228.69144 -122.113548)
		(width 0.127)
		(layer "In15.Cu")
		(net "FM_CPU_RMCA_CATERR_DLY_LVT3_R_N")
	)
	(segment
		(start 241.962178 -122.761248)
		(end 233.189018 -122.761248)
		(width 0.127)
		(layer "In15.Cu")
		(net "FM_CPU_RMCA_CATERR_DLY_LVT3_R_N")
	)
	(segment
		(start 184.36844 -120.975628)
		(end 183.97982 -120.975628)
		(width 0.127)
		(layer "In15.Cu")
		(net "FM_CPU_RMCA_CATERR_DLY_LVT3_R_N")
	)
	(segment
		(start 245.022878 -125.821948)
		(end 241.962178 -122.761248)
		(width 0.127)
		(layer "In15.Cu")
		(net "FM_CPU_RMCA_CATERR_DLY_LVT3_R_N")
	)
	(segment
		(start 182.361586 -120.174766)
		(end 182.153814 -119.966994)
		(width 0.127)
		(layer "In15.Cu")
		(net "FM_CPU_RMCA_CATERR_DLY_LVT3_R_N")
	)
	(segment
		(start 183.75376 -120.401588)
		(end 183.526938 -120.174766)
		(width 0.127)
		(layer "In15.Cu")
		(net "FM_CPU_RMCA_CATERR_DLY_LVT3_R_N")
	)
	(segment
		(start 194.780154 -129.410968)
		(end 194.57924 -129.210054)
		(width 0.127)
		(layer "In15.Cu")
		(net "FM_CPU_RMCA_CATERR_DLY_LVT3_R_N")
	)
	(segment
		(start 184.55132 -121.595388)
		(end 184.55132 -121.158508)
		(width 0.127)
		(layer "In15.Cu")
		(net "FM_CPU_RMCA_CATERR_DLY_LVT3_R_N")
	)
	(segment
		(start 181.56936 -119.370348)
		(end 181.355492 -119.15648)
		(width 0.127)
		(layer "In15.Cu")
		(net "FM_CPU_RMCA_CATERR_DLY_LVT3_R_N")
	)
	(segment
		(start 188.82106 -124.767848)
		(end 187.18784 -124.767848)
		(width 0.127)
		(layer "In15.Cu")
		(net "FM_CPU_RMCA_CATERR_DLY_LVT3_R_N")
	)
	(segment
		(start 320.09588 -121.249948)
		(end 286.34944 -121.249948)
		(width 0.127)
		(layer "In15.Cu")
		(net "FM_CPU_RMCA_CATERR_DLY_LVT3_R_N")
	)
	(segment
		(start 185.42508 -123.005088)
		(end 185.42508 -122.032268)
		(width 0.127)
		(layer "In15.Cu")
		(net "FM_CPU_RMCA_CATERR_DLY_LVT3_R_N")
	)
	(segment
		(start 207.6323 -127.051308)
		(end 207.07096 -127.612648)
		(width 0.127)
		(layer "In15.Cu")
		(net "FM_CPU_RMCA_CATERR_DLY_LVT3_R_N")
	)
	(segment
		(start 194.57924 -129.210054)
		(end 193.263266 -129.210054)
		(width 0.127)
		(layer "In15.Cu")
		(net "FM_CPU_RMCA_CATERR_DLY_LVT3_R_N")
	)
	(segment
		(start 197.590156 -129.410968)
		(end 194.780154 -129.410968)
		(width 0.127)
		(layer "In15.Cu")
		(net "FM_CPU_RMCA_CATERR_DLY_LVT3_R_N")
	)
	(segment
		(start 181.355492 -119.15648)
		(end 181.355492 -117.775228)
		(width 0.127)
		(layer "In15.Cu")
		(net "FM_CPU_RMCA_CATERR_DLY_LVT3_R_N")
	)
	(segment
		(start 184.7342 -121.778268)
		(end 184.55132 -121.595388)
		(width 0.127)
		(layer "In15.Cu")
		(net "FM_CPU_RMCA_CATERR_DLY_LVT3_R_N")
	)
	(segment
		(start 248.725182 -125.821948)
		(end 245.022878 -125.821948)
		(width 0.127)
		(layer "In15.Cu")
		(net "FM_CPU_RMCA_CATERR_DLY_LVT3_R_N")
	)
	(segment
		(start 183.75376 -120.749568)
		(end 183.75376 -120.401588)
		(width 0.127)
		(layer "In15.Cu")
		(net "FM_CPU_RMCA_CATERR_DLY_LVT3_R_N")
	)
	(segment
		(start 233.189018 -122.761248)
		(end 232.541318 -122.113548)
		(width 0.127)
		(layer "In15.Cu")
		(net "FM_CPU_RMCA_CATERR_DLY_LVT3_R_N")
	)
	(segment
		(start 283.87294 -123.726448)
		(end 250.820682 -123.726448)
		(width 0.127)
		(layer "In15.Cu")
		(net "FM_CPU_RMCA_CATERR_DLY_LVT3_R_N")
	)
	(segment
		(start 198.387716 -128.613408)
		(end 197.590156 -129.410968)
		(width 0.127)
		(layer "In15.Cu")
		(net "FM_CPU_RMCA_CATERR_DLY_LVT3_R_N")
	)
	(segment
		(start 187.18784 -124.767848)
		(end 185.42508 -123.005088)
		(width 0.127)
		(layer "In15.Cu")
		(net "FM_CPU_RMCA_CATERR_DLY_LVT3_R_N")
	)
	(segment
		(start 215.11641 -127.051308)
		(end 207.6323 -127.051308)
		(width 0.127)
		(layer "In15.Cu")
		(net "FM_CPU_RMCA_CATERR_DLY_LVT3_R_N")
	)
	(segment
		(start 250.820682 -123.726448)
		(end 248.725182 -125.821948)
		(width 0.127)
		(layer "In15.Cu")
		(net "FM_CPU_RMCA_CATERR_DLY_LVT3_R_N")
	)
	(segment
		(start 228.01072 -121.432828)
		(end 220.73489 -121.432828)
		(width 0.127)
		(layer "In15.Cu")
		(net "FM_CPU_RMCA_CATERR_DLY_LVT3_R_N")
	)
	(segment
		(start 184.55132 -121.158508)
		(end 184.36844 -120.975628)
		(width 0.127)
		(layer "In15.Cu")
		(net "FM_CPU_RMCA_CATERR_DLY_LVT3_R_N")
	)
	(segment
		(start 220.73489 -121.432828)
		(end 215.11641 -127.051308)
		(width 0.127)
		(layer "In15.Cu")
		(net "FM_CPU_RMCA_CATERR_DLY_LVT3_R_N")
	)
	(segment
		(start 183.97982 -120.975628)
		(end 183.75376 -120.749568)
		(width 0.127)
		(layer "In15.Cu")
		(net "FM_CPU_RMCA_CATERR_DLY_LVT3_R_N")
	)
	(segment
		(start 181.355492 -117.775228)
		(end 180.955696 -117.375432)
		(width 0.127)
		(layer "In15.Cu")
		(net "FM_CPU_RMCA_CATERR_DLY_LVT3_R_N")
	)
	(segment
		(start 205.866746 -127.206248)
		(end 200.815956 -127.206248)
		(width 0.127)
		(layer "In15.Cu")
		(net "FM_CPU_RMCA_CATERR_DLY_LVT3_R_N")
	)
	(segment
		(start 228.69144 -122.113548)
		(end 228.01072 -121.432828)
		(width 0.127)
		(layer "In15.Cu")
		(net "FM_CPU_RMCA_CATERR_DLY_LVT3_R_N")
	)
	(segment
		(start 206.273146 -127.612648)
		(end 205.866746 -127.206248)
		(width 0.127)
		(layer "In15.Cu")
		(net "FM_CPU_RMCA_CATERR_DLY_LVT3_R_N")
	)
	(segment
		(start 200.815956 -127.206248)
		(end 199.408796 -128.613408)
		(width 0.127)
		(layer "In15.Cu")
		(net "FM_CPU_RMCA_CATERR_DLY_LVT3_R_N")
	)
	(segment
		(start 185.17108 -121.778268)
		(end 184.7342 -121.778268)
		(width 0.127)
		(layer "In15.Cu")
		(net "FM_CPU_RMCA_CATERR_DLY_LVT3_R_N")
	)
	(segment
		(start 182.153814 -119.966994)
		(end 182.153814 -119.525288)
		(width 0.127)
		(layer "In15.Cu")
		(net "FM_CPU_RMCA_CATERR_DLY_LVT3_R_N")
	)
	(segment
		(start 185.42508 -122.032268)
		(end 185.17108 -121.778268)
		(width 0.127)
		(layer "In15.Cu")
		(net "FM_CPU_RMCA_CATERR_DLY_LVT3_R_N")
	)
	(segment
		(start 193.263266 -129.210054)
		(end 188.82106 -124.767848)
		(width 0.127)
		(layer "In15.Cu")
		(net "FM_CPU_RMCA_CATERR_DLY_LVT3_R_N")
	)
	(segment
		(start 183.526938 -120.174766)
		(end 182.361586 -120.174766)
		(width 0.127)
		(layer "In15.Cu")
		(net "FM_CPU_RMCA_CATERR_DLY_LVT3_R_N")
	)
	(segment
		(start 207.07096 -127.612648)
		(end 206.273146 -127.612648)
		(width 0.127)
		(layer "In15.Cu")
		(net "FM_CPU_RMCA_CATERR_DLY_LVT3_R_N")
	)
	(segment
		(start 181.998874 -119.370348)
		(end 181.56936 -119.370348)
		(width 0.127)
		(layer "In15.Cu")
		(net "FM_CPU_RMCA_CATERR_DLY_LVT3_R_N")
	)
	(segment
		(start 182.153814 -119.525288)
		(end 181.998874 -119.370348)
		(width 0.127)
		(layer "In15.Cu")
		(net "FM_CPU_RMCA_CATERR_DLY_LVT3_R_N")
	)
	(segment
		(start 286.34944 -121.249948)
		(end 283.87294 -123.726448)
		(width 0.127)
		(layer "In15.Cu")
		(net "FM_CPU_RMCA_CATERR_DLY_LVT3_R_N")
	)
	(segment
		(start 199.408796 -128.613408)
		(end 198.387716 -128.613408)
		(width 0.127)
		(layer "In15.Cu")
		(net "FM_CPU_RMCA_CATERR_DLY_LVT3_R_N")
	)
	(segment
		(start 350.292416 -261.522972)
		(end 350.292416 -262.058658)
		(width 0.12954)
		(layer "F.Cu")
		(net "FM_CPU_FBRK_DEBUG_R_N")
	)
	(segment
		(start 309.48884 -126.708408)
		(end 290.80968 -145.387568)
		(width 0.12954)
		(layer "F.Cu")
		(net "FM_CPU_FBRK_DEBUG_R_N")
	)
	(segment
		(start 219.6465 -150.231348)
		(end 218.9734 -149.558248)
		(width 0.12954)
		(layer "F.Cu")
		(net "FM_CPU_FBRK_DEBUG_R_N")
	)
	(segment
		(start 254.90424 -145.387568)
		(end 250.06046 -150.231348)
		(width 0.12954)
		(layer "F.Cu")
		(net "FM_CPU_FBRK_DEBUG_R_N")
	)
	(segment
		(start 250.06046 -150.231348)
		(end 219.6465 -150.231348)
		(width 0.12954)
		(layer "F.Cu")
		(net "FM_CPU_FBRK_DEBUG_R_N")
	)
	(segment
		(start 329.34402 -117.719348)
		(end 329.34402 -119.725948)
		(width 0.12954)
		(layer "F.Cu")
		(net "FM_CPU_FBRK_DEBUG_R_N")
	)
	(segment
		(start 404.463758 -57.734708)
		(end 404.406862 -57.791604)
		(width 0.12954)
		(layer "F.Cu")
		(net "FM_CPU_FBRK_DEBUG_R_N")
	)
	(segment
		(start 329.34402 -119.725948)
		(end 322.36156 -126.708408)
		(width 0.12954)
		(layer "F.Cu")
		(net "FM_CPU_FBRK_DEBUG_R_N")
	)
	(segment
		(start 211.572094 -149.558248)
		(end 211.113624 -150.016718)
		(width 0.12954)
		(layer "F.Cu")
		(net "FM_CPU_FBRK_DEBUG_R_N")
	)
	(segment
		(start 208.298288 -150.016718)
		(end 207.839818 -149.558248)
		(width 0.12954)
		(layer "F.Cu")
		(net "FM_CPU_FBRK_DEBUG_R_N")
	)
	(segment
		(start 350.292162 -261.522718)
		(end 350.292416 -261.522972)
		(width 0.12954)
		(layer "F.Cu")
		(net "FM_CPU_FBRK_DEBUG_R_N")
	)
	(segment
		(start 207.839818 -149.558248)
		(end 204.89545 -149.558248)
		(width 0.12954)
		(layer "F.Cu")
		(net "FM_CPU_FBRK_DEBUG_R_N")
	)
	(segment
		(start 407.39568 -56.622188)
		(end 406.28316 -57.734708)
		(width 0.12954)
		(layer "F.Cu")
		(net "FM_CPU_FBRK_DEBUG_R_N")
	)
	(segment
		(start 290.80968 -145.387568)
		(end 254.90424 -145.387568)
		(width 0.12954)
		(layer "F.Cu")
		(net "FM_CPU_FBRK_DEBUG_R_N")
	)
	(segment
		(start 218.9734 -149.558248)
		(end 211.572094 -149.558248)
		(width 0.12954)
		(layer "F.Cu")
		(net "FM_CPU_FBRK_DEBUG_R_N")
	)
	(segment
		(start 204.89545 -149.558248)
		(end 204.58303 -149.245828)
		(width 0.12954)
		(layer "F.Cu")
		(net "FM_CPU_FBRK_DEBUG_R_N")
	)
	(segment
		(start 102.352094 -261.522718)
		(end 102.352348 -261.522972)
		(width 0.12954)
		(layer "F.Cu")
		(net "FM_CPU_FBRK_DEBUG_R_N")
	)
	(segment
		(start 211.113624 -150.016718)
		(end 208.298288 -150.016718)
		(width 0.12954)
		(layer "F.Cu")
		(net "FM_CPU_FBRK_DEBUG_R_N")
	)
	(segment
		(start 322.36156 -126.708408)
		(end 309.48884 -126.708408)
		(width 0.12954)
		(layer "F.Cu")
		(net "FM_CPU_FBRK_DEBUG_R_N")
	)
	(segment
		(start 102.352348 -261.522972)
		(end 102.352348 -262.058658)
		(width 0.12954)
		(layer "F.Cu")
		(net "FM_CPU_FBRK_DEBUG_R_N")
	)
	(segment
		(start 406.28316 -57.734708)
		(end 404.463758 -57.734708)
		(width 0.12954)
		(layer "F.Cu")
		(net "FM_CPU_FBRK_DEBUG_R_N")
	)
	(via
		(at 324.475094 -264.633456)
		(size 0.6604)
		(drill 0.3302)
		(layers "F.Cu" "B.Cu")
		(net "FM_CPU_FBRK_DEBUG_R_N")
	)
	(via
		(at 57.1246 -181.176422)
		(size 0.508)
		(drill 0.254)
		(layers "F.Cu" "B.Cu")
		(net "FM_CPU_FBRK_DEBUG_R_N")
	)
	(via
		(at 75.174348 -172.560996)
		(size 0.508)
		(drill 0.254)
		(layers "F.Cu" "B.Cu")
		(net "FM_CPU_FBRK_DEBUG_R_N")
	)
	(via
		(at 329.34402 -117.719348)
		(size 0.508)
		(drill 0.254)
		(layers "F.Cu" "B.Cu")
		(net "FM_CPU_FBRK_DEBUG_R_N")
	)
	(via
		(at 101.749606 -146.109944)
		(size 0.508)
		(drill 0.254)
		(layers "F.Cu" "B.Cu")
		(net "FM_CPU_FBRK_DEBUG_R_N")
	)
	(via
		(at 102.352348 -262.058658)
		(size 0.4572)
		(drill 0.2032)
		(layers "F.Cu" "B.Cu")
		(net "FM_CPU_FBRK_DEBUG_R_N")
	)
	(via
		(at 204.58303 -149.245828)
		(size 0.508)
		(drill 0.254)
		(layers "F.Cu" "B.Cu")
		(net "FM_CPU_FBRK_DEBUG_R_N")
	)
	(via
		(at 407.39568 -56.622188)
		(size 0.508)
		(drill 0.254)
		(layers "F.Cu" "B.Cu")
		(net "FM_CPU_FBRK_DEBUG_R_N")
	)
	(via
		(at 350.292416 -262.058658)
		(size 0.4572)
		(drill 0.2032)
		(layers "F.Cu" "B.Cu")
		(net "FM_CPU_FBRK_DEBUG_R_N")
	)
	(segment
		(start 290.072318 -199.18299)
		(end 290.742878 -199.85355)
		(width 0.12954)
		(layer "B.Cu")
		(net "FM_CPU_FBRK_DEBUG_R_N")
	)
	(segment
		(start 99.34575 -261.7343)
		(end 99.331018 -261.742936)
		(width 0.0889)
		(layer "B.Cu")
		(net "FM_CPU_FBRK_DEBUG_R_N")
	)
	(segment
		(start 101.749606 -146.109944)
		(end 101.695758 -146.163792)
		(width 0.12954)
		(layer "B.Cu")
		(net "FM_CPU_FBRK_DEBUG_R_N")
	)
	(segment
		(start 315.246258 -266.71905)
		(end 316.300358 -265.66495)
		(width 0.12954)
		(layer "B.Cu")
		(net "FM_CPU_FBRK_DEBUG_R_N")
	)
	(segment
		(start 90.322146 -261.7343)
		(end 90.233246 -261.682992)
		(width 0.0889)
		(layer "B.Cu")
		(net "FM_CPU_FBRK_DEBUG_R_N")
	)
	(segment
		(start 316.300358 -265.66495)
		(end 322.24472 -265.66495)
		(width 0.12954)
		(layer "B.Cu")
		(net "FM_CPU_FBRK_DEBUG_R_N")
	)
	(segment
		(start 64.14008 -241.010948)
		(end 63.07328 -241.010948)
		(width 0.12954)
		(layer "B.Cu")
		(net "FM_CPU_FBRK_DEBUG_R_N")
	)
	(segment
		(start 271.317974 -185.57621)
		(end 284.837124 -185.57621)
		(width 0.12954)
		(layer "B.Cu")
		(net "FM_CPU_FBRK_DEBUG_R_N")
	)
	(segment
		(start 62.89548 -241.188748)
		(end 61.47308 -241.188748)
		(width 0.12954)
		(layer "B.Cu")
		(net "FM_CPU_FBRK_DEBUG_R_N")
	)
	(segment
		(start 307.542438 -266.52093)
		(end 310.846978 -266.52093)
		(width 0.12954)
		(layer "B.Cu")
		(net "FM_CPU_FBRK_DEBUG_R_N")
	)
	(segment
		(start 59.66968 -240.096548)
		(end 58.99658 -239.423448)
		(width 0.12954)
		(layer "B.Cu")
		(net "FM_CPU_FBRK_DEBUG_R_N")
	)
	(segment
		(start 294.6654 -256.657348)
		(end 298.191936 -256.657348)
		(width 0.12954)
		(layer "B.Cu")
		(net "FM_CPU_FBRK_DEBUG_R_N")
	)
	(segment
		(start 57.10174 -181.199282)
		(end 57.1246 -181.176422)
		(width 0.12954)
		(layer "B.Cu")
		(net "FM_CPU_FBRK_DEBUG_R_N")
	)
	(segment
		(start 290.742878 -247.47093)
		(end 292.091618 -248.81967)
		(width 0.12954)
		(layer "B.Cu")
		(net "FM_CPU_FBRK_DEBUG_R_N")
	)
	(segment
		(start 334.487012 -261.65937)
		(end 331.88402 -261.65937)
		(width 0.12954)
		(layer "B.Cu")
		(net "FM_CPU_FBRK_DEBUG_R_N")
	)
	(segment
		(start 299.643038 -262.66013)
		(end 300.039278 -263.05637)
		(width 0.12954)
		(layer "B.Cu")
		(net "FM_CPU_FBRK_DEBUG_R_N")
	)
	(segment
		(start 347.285818 -261.7343)
		(end 347.271086 -261.742936)
		(width 0.0889)
		(layer "B.Cu")
		(net "FM_CPU_FBRK_DEBUG_R_N")
	)
	(segment
		(start 323.276214 -264.633456)
		(end 324.475094 -264.633456)
		(width 0.12954)
		(layer "B.Cu")
		(net "FM_CPU_FBRK_DEBUG_R_N")
	)
	(segment
		(start 73.61428 -256.301748)
		(end 73.61428 -247.157748)
		(width 0.12954)
		(layer "B.Cu")
		(net "FM_CPU_FBRK_DEBUG_R_N")
	)
	(segment
		(start 102.352348 -262.058658)
		(end 101.80447 -261.804912)
		(width 0.0889)
		(layer "B.Cu")
		(net "FM_CPU_FBRK_DEBUG_R_N")
	)
	(segment
		(start 63.07328 -241.010948)
		(end 62.89548 -241.188748)
		(width 0.12954)
		(layer "B.Cu")
		(net "FM_CPU_FBRK_DEBUG_R_N")
	)
	(segment
		(start 343.526618 -261.7343)
		(end 343.511886 -261.742936)
		(width 0.0889)
		(layer "B.Cu")
		(net "FM_CPU_FBRK_DEBUG_R_N")
	)
	(segment
		(start 88.249506 -261.664958)
		(end 87.509604 -261.65937)
		(width 0.0889)
		(layer "B.Cu")
		(net "FM_CPU_FBRK_DEBUG_R_N")
	)
	(segment
		(start 91.82735 -261.7343)
		(end 91.816936 -261.740396)
		(width 0.0889)
		(layer "B.Cu")
		(net "FM_CPU_FBRK_DEBUG_R_N")
	)
	(segment
		(start 88.444324 -261.71906)
		(end 88.440514 -261.717028)
		(width 0.0889)
		(layer "B.Cu")
		(net "FM_CPU_FBRK_DEBUG_R_N")
	)
	(segment
		(start 348.225618 -261.7343)
		(end 348.210886 -261.742936)
		(width 0.0889)
		(layer "B.Cu")
		(net "FM_CPU_FBRK_DEBUG_R_N")
	)
	(segment
		(start 300.737778 -263.47039)
		(end 300.737778 -264.25017)
		(width 0.12954)
		(layer "B.Cu")
		(net "FM_CPU_FBRK_DEBUG_R_N")
	)
	(segment
		(start 292.091618 -248.81967)
		(end 292.091618 -251.74575)
		(width 0.12954)
		(layer "B.Cu")
		(net "FM_CPU_FBRK_DEBUG_R_N")
	)
	(segment
		(start 93.70695 -261.7343)
		(end 93.692218 -261.742936)
		(width 0.0889)
		(layer "B.Cu")
		(net "FM_CPU_FBRK_DEBUG_R_N")
	)
	(segment
		(start 300.039278 -263.05637)
		(end 300.323758 -263.05637)
		(width 0.12954)
		(layer "B.Cu")
		(net "FM_CPU_FBRK_DEBUG_R_N")
	)
	(segment
		(start 92.76715 -261.7343)
		(end 92.752418 -261.742936)
		(width 0.0889)
		(layer "B.Cu")
		(net "FM_CPU_FBRK_DEBUG_R_N")
	)
	(segment
		(start 337.976718 -261.682992)
		(end 337.888072 -261.734046)
		(width 0.0889)
		(layer "B.Cu")
		(net "FM_CPU_FBRK_DEBUG_R_N")
	)
	(segment
		(start 303.724818 -266.67587)
		(end 307.387498 -266.67587)
		(width 0.12954)
		(layer "B.Cu")
		(net "FM_CPU_FBRK_DEBUG_R_N")
	)
	(segment
		(start 302.929798 -265.88085)
		(end 303.724818 -266.67587)
		(width 0.12954)
		(layer "B.Cu")
		(net "FM_CPU_FBRK_DEBUG_R_N")
	)
	(segment
		(start 87.509604 -261.65937)
		(end 86.546944 -261.65937)
		(width 0.0889)
		(layer "B.Cu")
		(net "FM_CPU_FBRK_DEBUG_R_N")
	)
	(segment
		(start 96.52635 -261.7343)
		(end 96.511618 -261.742936)
		(width 0.0889)
		(layer "B.Cu")
		(net "FM_CPU_FBRK_DEBUG_R_N")
	)
	(segment
		(start 286.624522 -187.363608)
		(end 289.54222 -187.363608)
		(width 0.12954)
		(layer "B.Cu")
		(net "FM_CPU_FBRK_DEBUG_R_N")
	)
	(segment
		(start 100.28555 -261.7343)
		(end 100.270818 -261.742936)
		(width 0.0889)
		(layer "B.Cu")
		(net "FM_CPU_FBRK_DEBUG_R_N")
	)
	(segment
		(start 300.323758 -263.05637)
		(end 300.737778 -263.47039)
		(width 0.12954)
		(layer "B.Cu")
		(net "FM_CPU_FBRK_DEBUG_R_N")
	)
	(segment
		(start 55.1561 -200.210928)
		(end 57.10174 -198.265288)
		(width 0.12954)
		(layer "B.Cu")
		(net "FM_CPU_FBRK_DEBUG_R_N")
	)
	(segment
		(start 338.262214 -261.7343)
		(end 338.173314 -261.682992)
		(width 0.0889)
		(layer "B.Cu")
		(net "FM_CPU_FBRK_DEBUG_R_N")
	)
	(segment
		(start 302.368458 -265.88085)
		(end 302.929798 -265.88085)
		(width 0.12954)
		(layer "B.Cu")
		(net "FM_CPU_FBRK_DEBUG_R_N")
	)
	(segment
		(start 292.929818 -254.921766)
		(end 294.6654 -256.657348)
		(width 0.12954)
		(layer "B.Cu")
		(net "FM_CPU_FBRK_DEBUG_R_N")
	)
	(segment
		(start 292.091618 -251.74575)
		(end 292.929818 -252.58395)
		(width 0.12954)
		(layer "B.Cu")
		(net "FM_CPU_FBRK_DEBUG_R_N")
	)
	(segment
		(start 345.406472 -261.7343)
		(end 345.396058 -261.740396)
		(width 0.0889)
		(layer "B.Cu")
		(net "FM_CPU_FBRK_DEBUG_R_N")
	)
	(segment
		(start 207.617568 -154.570938)
		(end 240.312702 -154.570938)
		(width 0.12954)
		(layer "B.Cu")
		(net "FM_CPU_FBRK_DEBUG_R_N")
	)
	(segment
		(start 204.58303 -149.245828)
		(end 204.58303 -151.5364)
		(width 0.12954)
		(layer "B.Cu")
		(net "FM_CPU_FBRK_DEBUG_R_N")
	)
	(segment
		(start 331.88402 -261.65937)
		(end 328.909934 -264.633456)
		(width 0.12954)
		(layer "B.Cu")
		(net "FM_CPU_FBRK_DEBUG_R_N")
	)
	(segment
		(start 289.54222 -187.363608)
		(end 290.072318 -187.893706)
		(width 0.12954)
		(layer "B.Cu")
		(net "FM_CPU_FBRK_DEBUG_R_N")
	)
	(segment
		(start 341.647018 -261.7343)
		(end 341.632286 -261.742936)
		(width 0.0889)
		(layer "B.Cu")
		(net "FM_CPU_FBRK_DEBUG_R_N")
	)
	(segment
		(start 101.571552 -146.163792)
		(end 75.174348 -172.560996)
		(width 0.12954)
		(layer "B.Cu")
		(net "FM_CPU_FBRK_DEBUG_R_N")
	)
	(segment
		(start 322.24472 -265.66495)
		(end 323.276214 -264.633456)
		(width 0.12954)
		(layer "B.Cu")
		(net "FM_CPU_FBRK_DEBUG_R_N")
	)
	(segment
		(start 98.40595 -261.7343)
		(end 98.395536 -261.740396)
		(width 0.0889)
		(layer "B.Cu")
		(net "FM_CPU_FBRK_DEBUG_R_N")
	)
	(segment
		(start 298.191936 -256.657348)
		(end 299.643038 -258.10845)
		(width 0.12954)
		(layer "B.Cu")
		(net "FM_CPU_FBRK_DEBUG_R_N")
	)
	(segment
		(start 284.837124 -185.57621)
		(end 286.624522 -187.363608)
		(width 0.12954)
		(layer "B.Cu")
		(net "FM_CPU_FBRK_DEBUG_R_N")
	)
	(segment
		(start 60.38088 -240.096548)
		(end 59.66968 -240.096548)
		(width 0.12954)
		(layer "B.Cu")
		(net "FM_CPU_FBRK_DEBUG_R_N")
	)
	(segment
		(start 336.189574 -261.664958)
		(end 335.449672 -261.65937)
		(width 0.0889)
		(layer "B.Cu")
		(net "FM_CPU_FBRK_DEBUG_R_N")
	)
	(segment
		(start 73.61428 -247.157748)
		(end 69.22008 -242.763548)
		(width 0.12954)
		(layer "B.Cu")
		(net "FM_CPU_FBRK_DEBUG_R_N")
	)
	(segment
		(start 97.466404 -261.7343)
		(end 97.45599 -261.740396)
		(width 0.0889)
		(layer "B.Cu")
		(net "FM_CPU_FBRK_DEBUG_R_N")
	)
	(segment
		(start 95.58655 -261.7343)
		(end 95.571818 -261.742936)
		(width 0.0889)
		(layer "B.Cu")
		(net "FM_CPU_FBRK_DEBUG_R_N")
	)
	(segment
		(start 57.10174 -198.265288)
		(end 57.10174 -181.199282)
		(width 0.12954)
		(layer "B.Cu")
		(net "FM_CPU_FBRK_DEBUG_R_N")
	)
	(segment
		(start 53.88102 -200.952608)
		(end 54.6227 -200.210928)
		(width 0.12954)
		(layer "B.Cu")
		(net "FM_CPU_FBRK_DEBUG_R_N")
	)
	(segment
		(start 54.08168 -236.413548)
		(end 54.08168 -233.573828)
		(width 0.12954)
		(layer "B.Cu")
		(net "FM_CPU_FBRK_DEBUG_R_N")
	)
	(segment
		(start 86.546944 -261.65937)
		(end 78.971902 -261.65937)
		(width 0.12954)
		(layer "B.Cu")
		(net "FM_CPU_FBRK_DEBUG_R_N")
	)
	(segment
		(start 346.346018 -261.7343)
		(end 346.335604 -261.740396)
		(width 0.0889)
		(layer "B.Cu")
		(net "FM_CPU_FBRK_DEBUG_R_N")
	)
	(segment
		(start 311.045098 -266.71905)
		(end 315.246258 -266.71905)
		(width 0.12954)
		(layer "B.Cu")
		(net "FM_CPU_FBRK_DEBUG_R_N")
	)
	(segment
		(start 65.89268 -242.763548)
		(end 64.14008 -241.010948)
		(width 0.12954)
		(layer "B.Cu")
		(net "FM_CPU_FBRK_DEBUG_R_N")
	)
	(segment
		(start 55.87238 -236.985048)
		(end 54.65318 -236.985048)
		(width 0.12954)
		(layer "B.Cu")
		(net "FM_CPU_FBRK_DEBUG_R_N")
	)
	(segment
		(start 90.03665 -261.682992)
		(end 89.948004 -261.734046)
		(width 0.0889)
		(layer "B.Cu")
		(net "FM_CPU_FBRK_DEBUG_R_N")
	)
	(segment
		(start 61.47308 -241.188748)
		(end 60.38088 -240.096548)
		(width 0.12954)
		(layer "B.Cu")
		(net "FM_CPU_FBRK_DEBUG_R_N")
	)
	(segment
		(start 340.707218 -261.7343)
		(end 340.692486 -261.742936)
		(width 0.0889)
		(layer "B.Cu")
		(net "FM_CPU_FBRK_DEBUG_R_N")
	)
	(segment
		(start 344.466418 -261.7343)
		(end 344.451686 -261.742936)
		(width 0.0889)
		(layer "B.Cu")
		(net "FM_CPU_FBRK_DEBUG_R_N")
	)
	(segment
		(start 54.65318 -236.985048)
		(end 54.08168 -236.413548)
		(width 0.12954)
		(layer "B.Cu")
		(net "FM_CPU_FBRK_DEBUG_R_N")
	)
	(segment
		(start 299.643038 -258.10845)
		(end 299.643038 -262.66013)
		(width 0.12954)
		(layer "B.Cu")
		(net "FM_CPU_FBRK_DEBUG_R_N")
	)
	(segment
		(start 78.971902 -261.65937)
		(end 73.61428 -256.301748)
		(width 0.12954)
		(layer "B.Cu")
		(net "FM_CPU_FBRK_DEBUG_R_N")
	)
	(segment
		(start 307.387498 -266.67587)
		(end 307.542438 -266.52093)
		(width 0.12954)
		(layer "B.Cu")
		(net "FM_CPU_FBRK_DEBUG_R_N")
	)
	(segment
		(start 89.409778 -261.733792)
		(end 89.384124 -261.71906)
		(width 0.0889)
		(layer "B.Cu")
		(net "FM_CPU_FBRK_DEBUG_R_N")
	)
	(segment
		(start 58.31078 -239.423448)
		(end 55.87238 -236.985048)
		(width 0.12954)
		(layer "B.Cu")
		(net "FM_CPU_FBRK_DEBUG_R_N")
	)
	(segment
		(start 335.449672 -261.65937)
		(end 334.487012 -261.65937)
		(width 0.0889)
		(layer "B.Cu")
		(net "FM_CPU_FBRK_DEBUG_R_N")
	)
	(segment
		(start 204.58303 -151.5364)
		(end 207.617568 -154.570938)
		(width 0.12954)
		(layer "B.Cu")
		(net "FM_CPU_FBRK_DEBUG_R_N")
	)
	(segment
		(start 101.695758 -146.163792)
		(end 101.571552 -146.163792)
		(width 0.12954)
		(layer "B.Cu")
		(net "FM_CPU_FBRK_DEBUG_R_N")
	)
	(segment
		(start 53.88102 -233.373168)
		(end 53.88102 -200.952608)
		(width 0.12954)
		(layer "B.Cu")
		(net "FM_CPU_FBRK_DEBUG_R_N")
	)
	(segment
		(start 328.909934 -264.633456)
		(end 324.475094 -264.633456)
		(width 0.12954)
		(layer "B.Cu")
		(net "FM_CPU_FBRK_DEBUG_R_N")
	)
	(segment
		(start 300.737778 -264.25017)
		(end 302.368458 -265.88085)
		(width 0.12954)
		(layer "B.Cu")
		(net "FM_CPU_FBRK_DEBUG_R_N")
	)
	(segment
		(start 350.292416 -262.058658)
		(end 349.744538 -261.804912)
		(width 0.0889)
		(layer "B.Cu")
		(net "FM_CPU_FBRK_DEBUG_R_N")
	)
	(segment
		(start 240.312702 -154.570938)
		(end 271.317974 -185.57621)
		(width 0.12954)
		(layer "B.Cu")
		(net "FM_CPU_FBRK_DEBUG_R_N")
	)
	(segment
		(start 290.072318 -187.893706)
		(end 290.072318 -199.18299)
		(width 0.12954)
		(layer "B.Cu")
		(net "FM_CPU_FBRK_DEBUG_R_N")
	)
	(segment
		(start 290.742878 -199.85355)
		(end 290.742878 -247.47093)
		(width 0.12954)
		(layer "B.Cu")
		(net "FM_CPU_FBRK_DEBUG_R_N")
	)
	(segment
		(start 310.846978 -266.52093)
		(end 311.045098 -266.71905)
		(width 0.12954)
		(layer "B.Cu")
		(net "FM_CPU_FBRK_DEBUG_R_N")
	)
	(segment
		(start 69.22008 -242.763548)
		(end 65.89268 -242.763548)
		(width 0.12954)
		(layer "B.Cu")
		(net "FM_CPU_FBRK_DEBUG_R_N")
	)
	(segment
		(start 58.99658 -239.423448)
		(end 58.31078 -239.423448)
		(width 0.12954)
		(layer "B.Cu")
		(net "FM_CPU_FBRK_DEBUG_R_N")
	)
	(segment
		(start 337.349846 -261.733792)
		(end 337.324192 -261.71906)
		(width 0.0889)
		(layer "B.Cu")
		(net "FM_CPU_FBRK_DEBUG_R_N")
	)
	(segment
		(start 54.6227 -200.210928)
		(end 55.1561 -200.210928)
		(width 0.12954)
		(layer "B.Cu")
		(net "FM_CPU_FBRK_DEBUG_R_N")
	)
	(segment
		(start 339.767418 -261.7343)
		(end 339.757004 -261.740396)
		(width 0.0889)
		(layer "B.Cu")
		(net "FM_CPU_FBRK_DEBUG_R_N")
	)
	(segment
		(start 54.08168 -233.573828)
		(end 53.88102 -233.373168)
		(width 0.12954)
		(layer "B.Cu")
		(net "FM_CPU_FBRK_DEBUG_R_N")
	)
	(segment
		(start 292.929818 -252.58395)
		(end 292.929818 -254.921766)
		(width 0.12954)
		(layer "B.Cu")
		(net "FM_CPU_FBRK_DEBUG_R_N")
	)
	(segment
		(start 336.384392 -261.71906)
		(end 336.380582 -261.717028)
		(width 0.0889)
		(layer "B.Cu")
		(net "FM_CPU_FBRK_DEBUG_R_N")
	)
	(arc
		(start 92.201746 -261.7343)
		(mid 92.014548 -261.684157)
		(end 91.82735 -261.7343)
		(width 0.0889)
		(layer "B.Cu")
		(net "FM_CPU_FBRK_DEBUG_R_N")
	)
	(arc
		(start 338.173314 -261.682992)
		(mid 338.075016 -261.656643)
		(end 337.976718 -261.682992)
		(width 0.0889)
		(layer "B.Cu")
		(net "FM_CPU_FBRK_DEBUG_R_N")
	)
	(arc
		(start 340.692486 -261.742936)
		(mid 340.416011 -261.810256)
		(end 340.141814 -261.7343)
		(width 0.0889)
		(layer "B.Cu")
		(net "FM_CPU_FBRK_DEBUG_R_N")
	)
	(arc
		(start 336.380582 -261.717028)
		(mid 336.288453 -261.67861)
		(end 336.189574 -261.664958)
		(width 0.0889)
		(layer "B.Cu")
		(net "FM_CPU_FBRK_DEBUG_R_N")
	)
	(arc
		(start 345.780868 -261.7343)
		(mid 345.59367 -261.684157)
		(end 345.406472 -261.7343)
		(width 0.0889)
		(layer "B.Cu")
		(net "FM_CPU_FBRK_DEBUG_R_N")
	)
	(arc
		(start 339.757004 -261.740396)
		(mid 339.478826 -261.810119)
		(end 339.202268 -261.7343)
		(width 0.0889)
		(layer "B.Cu")
		(net "FM_CPU_FBRK_DEBUG_R_N")
	)
	(arc
		(start 99.331018 -261.742936)
		(mid 99.054543 -261.810256)
		(end 98.780346 -261.7343)
		(width 0.0889)
		(layer "B.Cu")
		(net "FM_CPU_FBRK_DEBUG_R_N")
	)
	(arc
		(start 349.539814 -261.7343)
		(mid 349.352616 -261.684157)
		(end 349.165418 -261.7343)
		(width 0.0889)
		(layer "B.Cu")
		(net "FM_CPU_FBRK_DEBUG_R_N")
	)
	(arc
		(start 344.840814 -261.7343)
		(mid 344.653616 -261.684157)
		(end 344.466418 -261.7343)
		(width 0.0889)
		(layer "B.Cu")
		(net "FM_CPU_FBRK_DEBUG_R_N")
	)
	(arc
		(start 341.081614 -261.7343)
		(mid 340.894416 -261.684157)
		(end 340.707218 -261.7343)
		(width 0.0889)
		(layer "B.Cu")
		(net "FM_CPU_FBRK_DEBUG_R_N")
	)
	(arc
		(start 347.660214 -261.7343)
		(mid 347.473016 -261.684157)
		(end 347.285818 -261.7343)
		(width 0.0889)
		(layer "B.Cu")
		(net "FM_CPU_FBRK_DEBUG_R_N")
	)
	(arc
		(start 96.900746 -261.7343)
		(mid 96.713548 -261.684157)
		(end 96.52635 -261.7343)
		(width 0.0889)
		(layer "B.Cu")
		(net "FM_CPU_FBRK_DEBUG_R_N")
	)
	(arc
		(start 342.961214 -261.7343)
		(mid 342.774016 -261.684157)
		(end 342.586818 -261.7343)
		(width 0.0889)
		(layer "B.Cu")
		(net "FM_CPU_FBRK_DEBUG_R_N")
	)
	(arc
		(start 348.600014 -261.7343)
		(mid 348.412816 -261.684157)
		(end 348.225618 -261.7343)
		(width 0.0889)
		(layer "B.Cu")
		(net "FM_CPU_FBRK_DEBUG_R_N")
	)
	(arc
		(start 98.780346 -261.7343)
		(mid 98.593148 -261.684157)
		(end 98.40595 -261.7343)
		(width 0.0889)
		(layer "B.Cu")
		(net "FM_CPU_FBRK_DEBUG_R_N")
	)
	(arc
		(start 346.335604 -261.740396)
		(mid 346.057426 -261.810119)
		(end 345.780868 -261.7343)
		(width 0.0889)
		(layer "B.Cu")
		(net "FM_CPU_FBRK_DEBUG_R_N")
	)
	(arc
		(start 348.210886 -261.742936)
		(mid 347.934411 -261.810256)
		(end 347.660214 -261.7343)
		(width 0.0889)
		(layer "B.Cu")
		(net "FM_CPU_FBRK_DEBUG_R_N")
	)
	(arc
		(start 95.571818 -261.742936)
		(mid 95.295343 -261.810256)
		(end 95.021146 -261.7343)
		(width 0.0889)
		(layer "B.Cu")
		(net "FM_CPU_FBRK_DEBUG_R_N")
	)
	(arc
		(start 347.271086 -261.742936)
		(mid 346.994611 -261.810256)
		(end 346.720414 -261.7343)
		(width 0.0889)
		(layer "B.Cu")
		(net "FM_CPU_FBRK_DEBUG_R_N")
	)
	(arc
		(start 337.324192 -261.71906)
		(mid 337.136994 -261.668917)
		(end 336.949796 -261.71906)
		(width 0.0889)
		(layer "B.Cu")
		(net "FM_CPU_FBRK_DEBUG_R_N")
	)
	(arc
		(start 339.202268 -261.7343)
		(mid 339.01507 -261.684157)
		(end 338.827872 -261.7343)
		(width 0.0889)
		(layer "B.Cu")
		(net "FM_CPU_FBRK_DEBUG_R_N")
	)
	(arc
		(start 101.599746 -261.7343)
		(mid 101.412548 -261.684157)
		(end 101.22535 -261.7343)
		(width 0.0889)
		(layer "B.Cu")
		(net "FM_CPU_FBRK_DEBUG_R_N")
	)
	(arc
		(start 94.081346 -261.7343)
		(mid 93.894148 -261.684157)
		(end 93.70695 -261.7343)
		(width 0.0889)
		(layer "B.Cu")
		(net "FM_CPU_FBRK_DEBUG_R_N")
	)
	(arc
		(start 89.384124 -261.71906)
		(mid 89.196926 -261.668917)
		(end 89.009728 -261.71906)
		(width 0.0889)
		(layer "B.Cu")
		(net "FM_CPU_FBRK_DEBUG_R_N")
	)
	(arc
		(start 343.901014 -261.7343)
		(mid 343.713816 -261.684157)
		(end 343.526618 -261.7343)
		(width 0.0889)
		(layer "B.Cu")
		(net "FM_CPU_FBRK_DEBUG_R_N")
	)
	(arc
		(start 89.009728 -261.71906)
		(mid 88.727026 -261.794836)
		(end 88.444324 -261.71906)
		(width 0.0889)
		(layer "B.Cu")
		(net "FM_CPU_FBRK_DEBUG_R_N")
	)
	(arc
		(start 100.659946 -261.7343)
		(mid 100.472748 -261.684157)
		(end 100.28555 -261.7343)
		(width 0.0889)
		(layer "B.Cu")
		(net "FM_CPU_FBRK_DEBUG_R_N")
	)
	(arc
		(start 340.141814 -261.7343)
		(mid 339.954616 -261.684157)
		(end 339.767418 -261.7343)
		(width 0.0889)
		(layer "B.Cu")
		(net "FM_CPU_FBRK_DEBUG_R_N")
	)
	(arc
		(start 336.949796 -261.71906)
		(mid 336.667094 -261.794836)
		(end 336.384392 -261.71906)
		(width 0.0889)
		(layer "B.Cu")
		(net "FM_CPU_FBRK_DEBUG_R_N")
	)
	(arc
		(start 97.8408 -261.7343)
		(mid 97.653602 -261.684157)
		(end 97.466404 -261.7343)
		(width 0.0889)
		(layer "B.Cu")
		(net "FM_CPU_FBRK_DEBUG_R_N")
	)
	(arc
		(start 91.816936 -261.740396)
		(mid 91.538758 -261.810119)
		(end 91.2622 -261.7343)
		(width 0.0889)
		(layer "B.Cu")
		(net "FM_CPU_FBRK_DEBUG_R_N")
	)
	(arc
		(start 92.752418 -261.742936)
		(mid 92.475943 -261.810256)
		(end 92.201746 -261.7343)
		(width 0.0889)
		(layer "B.Cu")
		(net "FM_CPU_FBRK_DEBUG_R_N")
	)
	(arc
		(start 338.827872 -261.7343)
		(mid 338.54506 -261.810008)
		(end 338.262214 -261.7343)
		(width 0.0889)
		(layer "B.Cu")
		(net "FM_CPU_FBRK_DEBUG_R_N")
	)
	(arc
		(start 95.960946 -261.7343)
		(mid 95.773748 -261.684157)
		(end 95.58655 -261.7343)
		(width 0.0889)
		(layer "B.Cu")
		(net "FM_CPU_FBRK_DEBUG_R_N")
	)
	(arc
		(start 342.021414 -261.7343)
		(mid 341.834216 -261.684157)
		(end 341.647018 -261.7343)
		(width 0.0889)
		(layer "B.Cu")
		(net "FM_CPU_FBRK_DEBUG_R_N")
	)
	(arc
		(start 349.744538 -261.804912)
		(mid 349.638753 -261.779522)
		(end 349.539814 -261.7343)
		(width 0.0889)
		(layer "B.Cu")
		(net "FM_CPU_FBRK_DEBUG_R_N")
	)
	(arc
		(start 94.64675 -261.7343)
		(mid 94.364048 -261.810076)
		(end 94.081346 -261.7343)
		(width 0.0889)
		(layer "B.Cu")
		(net "FM_CPU_FBRK_DEBUG_R_N")
	)
	(arc
		(start 342.586818 -261.7343)
		(mid 342.304116 -261.810076)
		(end 342.021414 -261.7343)
		(width 0.0889)
		(layer "B.Cu")
		(net "FM_CPU_FBRK_DEBUG_R_N")
	)
	(arc
		(start 90.887804 -261.7343)
		(mid 90.604992 -261.810008)
		(end 90.322146 -261.7343)
		(width 0.0889)
		(layer "B.Cu")
		(net "FM_CPU_FBRK_DEBUG_R_N")
	)
	(arc
		(start 88.440514 -261.717028)
		(mid 88.348385 -261.67861)
		(end 88.249506 -261.664958)
		(width 0.0889)
		(layer "B.Cu")
		(net "FM_CPU_FBRK_DEBUG_R_N")
	)
	(arc
		(start 93.141546 -261.7343)
		(mid 92.954348 -261.684157)
		(end 92.76715 -261.7343)
		(width 0.0889)
		(layer "B.Cu")
		(net "FM_CPU_FBRK_DEBUG_R_N")
	)
	(arc
		(start 100.270818 -261.742936)
		(mid 99.994343 -261.810256)
		(end 99.720146 -261.7343)
		(width 0.0889)
		(layer "B.Cu")
		(net "FM_CPU_FBRK_DEBUG_R_N")
	)
	(arc
		(start 101.80447 -261.804912)
		(mid 101.698685 -261.779522)
		(end 101.599746 -261.7343)
		(width 0.0889)
		(layer "B.Cu")
		(net "FM_CPU_FBRK_DEBUG_R_N")
	)
	(arc
		(start 89.948004 -261.734046)
		(mid 89.678845 -261.806027)
		(end 89.409778 -261.733792)
		(width 0.0889)
		(layer "B.Cu")
		(net "FM_CPU_FBRK_DEBUG_R_N")
	)
	(arc
		(start 337.888072 -261.734046)
		(mid 337.618913 -261.806027)
		(end 337.349846 -261.733792)
		(width 0.0889)
		(layer "B.Cu")
		(net "FM_CPU_FBRK_DEBUG_R_N")
	)
	(arc
		(start 97.45599 -261.740396)
		(mid 97.177558 -261.810242)
		(end 96.900746 -261.7343)
		(width 0.0889)
		(layer "B.Cu")
		(net "FM_CPU_FBRK_DEBUG_R_N")
	)
	(arc
		(start 99.720146 -261.7343)
		(mid 99.532948 -261.684157)
		(end 99.34575 -261.7343)
		(width 0.0889)
		(layer "B.Cu")
		(net "FM_CPU_FBRK_DEBUG_R_N")
	)
	(arc
		(start 346.720414 -261.7343)
		(mid 346.533216 -261.684157)
		(end 346.346018 -261.7343)
		(width 0.0889)
		(layer "B.Cu")
		(net "FM_CPU_FBRK_DEBUG_R_N")
	)
	(arc
		(start 90.233246 -261.682992)
		(mid 90.134948 -261.656643)
		(end 90.03665 -261.682992)
		(width 0.0889)
		(layer "B.Cu")
		(net "FM_CPU_FBRK_DEBUG_R_N")
	)
	(arc
		(start 344.451686 -261.742936)
		(mid 344.175211 -261.810256)
		(end 343.901014 -261.7343)
		(width 0.0889)
		(layer "B.Cu")
		(net "FM_CPU_FBRK_DEBUG_R_N")
	)
	(arc
		(start 95.021146 -261.7343)
		(mid 94.833948 -261.684157)
		(end 94.64675 -261.7343)
		(width 0.0889)
		(layer "B.Cu")
		(net "FM_CPU_FBRK_DEBUG_R_N")
	)
	(arc
		(start 93.692218 -261.742936)
		(mid 93.415743 -261.810256)
		(end 93.141546 -261.7343)
		(width 0.0889)
		(layer "B.Cu")
		(net "FM_CPU_FBRK_DEBUG_R_N")
	)
	(arc
		(start 345.396058 -261.740396)
		(mid 345.117626 -261.810242)
		(end 344.840814 -261.7343)
		(width 0.0889)
		(layer "B.Cu")
		(net "FM_CPU_FBRK_DEBUG_R_N")
	)
	(arc
		(start 98.395536 -261.740396)
		(mid 98.117358 -261.810119)
		(end 97.8408 -261.7343)
		(width 0.0889)
		(layer "B.Cu")
		(net "FM_CPU_FBRK_DEBUG_R_N")
	)
	(arc
		(start 91.2622 -261.7343)
		(mid 91.075002 -261.684157)
		(end 90.887804 -261.7343)
		(width 0.0889)
		(layer "B.Cu")
		(net "FM_CPU_FBRK_DEBUG_R_N")
	)
	(arc
		(start 349.165418 -261.7343)
		(mid 348.882716 -261.810076)
		(end 348.600014 -261.7343)
		(width 0.0889)
		(layer "B.Cu")
		(net "FM_CPU_FBRK_DEBUG_R_N")
	)
	(arc
		(start 101.22535 -261.7343)
		(mid 100.942648 -261.810076)
		(end 100.659946 -261.7343)
		(width 0.0889)
		(layer "B.Cu")
		(net "FM_CPU_FBRK_DEBUG_R_N")
	)
	(arc
		(start 343.511886 -261.742936)
		(mid 343.235411 -261.810256)
		(end 342.961214 -261.7343)
		(width 0.0889)
		(layer "B.Cu")
		(net "FM_CPU_FBRK_DEBUG_R_N")
	)
	(arc
		(start 96.511618 -261.742936)
		(mid 96.235143 -261.810256)
		(end 95.960946 -261.7343)
		(width 0.0889)
		(layer "B.Cu")
		(net "FM_CPU_FBRK_DEBUG_R_N")
	)
	(arc
		(start 341.632286 -261.742936)
		(mid 341.355811 -261.810256)
		(end 341.081614 -261.7343)
		(width 0.0889)
		(layer "B.Cu")
		(net "FM_CPU_FBRK_DEBUG_R_N")
	)
	(segment
		(start 182.108094 -148.10232)
		(end 181.601872 -148.10232)
		(width 0.127)
		(layer "In15.Cu")
		(net "FM_CPU_FBRK_DEBUG_R_N")
	)
	(segment
		(start 386.646674 -69.57822)
		(end 375.898156 -69.57822)
		(width 0.127)
		(layer "In15.Cu")
		(net "FM_CPU_FBRK_DEBUG_R_N")
	)
	(segment
		(start 176.378616 -148.274786)
		(end 175.91532 -147.81149)
		(width 0.127)
		(layer "In15.Cu")
		(net "FM_CPU_FBRK_DEBUG_R_N")
	)
	(segment
		(start 103.57485 -147.81149)
		(end 101.873304 -146.109944)
		(width 0.127)
		(layer "In15.Cu")
		(net "FM_CPU_FBRK_DEBUG_R_N")
	)
	(segment
		(start 375.898156 -69.57822)
		(end 373.112792 -72.363584)
		(width 0.127)
		(layer "In15.Cu")
		(net "FM_CPU_FBRK_DEBUG_R_N")
	)
	(segment
		(start 72.625458 -180.279548)
		(end 70.504558 -182.400448)
		(width 0.127)
		(layer "In15.Cu")
		(net "FM_CPU_FBRK_DEBUG_R_N")
	)
	(segment
		(start 181.429406 -148.274786)
		(end 176.378616 -148.274786)
		(width 0.127)
		(layer "In15.Cu")
		(net "FM_CPU_FBRK_DEBUG_R_N")
	)
	(segment
		(start 204.58303 -149.245828)
		(end 202.530456 -147.193254)
		(width 0.127)
		(layer "In15.Cu")
		(net "FM_CPU_FBRK_DEBUG_R_N")
	)
	(segment
		(start 407.39568 -56.622188)
		(end 404.133304 -56.622188)
		(width 0.127)
		(layer "In15.Cu")
		(net "FM_CPU_FBRK_DEBUG_R_N")
	)
	(segment
		(start 143.800068 -147.81149)
		(end 142.227554 -146.238976)
		(width 0.127)
		(layer "In15.Cu")
		(net "FM_CPU_FBRK_DEBUG_R_N")
	)
	(segment
		(start 331.40269 -115.660678)
		(end 329.34402 -117.719348)
		(width 0.127)
		(layer "In15.Cu")
		(net "FM_CPU_FBRK_DEBUG_R_N")
	)
	(segment
		(start 138.156696 -146.238976)
		(end 136.584182 -147.81149)
		(width 0.127)
		(layer "In15.Cu")
		(net "FM_CPU_FBRK_DEBUG_R_N")
	)
	(segment
		(start 75.174348 -172.560996)
		(end 76.88707 -174.273718)
		(width 0.127)
		(layer "In15.Cu")
		(net "FM_CPU_FBRK_DEBUG_R_N")
	)
	(segment
		(start 373.112792 -72.363584)
		(end 373.112792 -81.443068)
		(width 0.127)
		(layer "In15.Cu")
		(net "FM_CPU_FBRK_DEBUG_R_N")
	)
	(segment
		(start 385.94284 -94.273116)
		(end 385.94284 -104.775)
		(width 0.127)
		(layer "In15.Cu")
		(net "FM_CPU_FBRK_DEBUG_R_N")
	)
	(segment
		(start 385.94284 -104.775)
		(end 376.72264 -113.9952)
		(width 0.127)
		(layer "In15.Cu")
		(net "FM_CPU_FBRK_DEBUG_R_N")
	)
	(segment
		(start 187.70854 -150.155148)
		(end 184.160922 -150.155148)
		(width 0.127)
		(layer "In15.Cu")
		(net "FM_CPU_FBRK_DEBUG_R_N")
	)
	(segment
		(start 404.133304 -56.622188)
		(end 394.859256 -60.463684)
		(width 0.127)
		(layer "In15.Cu")
		(net "FM_CPU_FBRK_DEBUG_R_N")
	)
	(segment
		(start 184.160922 -150.155148)
		(end 182.108094 -148.10232)
		(width 0.127)
		(layer "In15.Cu")
		(net "FM_CPU_FBRK_DEBUG_R_N")
	)
	(segment
		(start 373.112792 -81.443068)
		(end 385.94284 -94.273116)
		(width 0.127)
		(layer "In15.Cu")
		(net "FM_CPU_FBRK_DEBUG_R_N")
	)
	(segment
		(start 57.489852 -181.541674)
		(end 57.1246 -181.176422)
		(width 0.127)
		(layer "In15.Cu")
		(net "FM_CPU_FBRK_DEBUG_R_N")
	)
	(segment
		(start 181.601872 -148.10232)
		(end 181.429406 -148.274786)
		(width 0.127)
		(layer "In15.Cu")
		(net "FM_CPU_FBRK_DEBUG_R_N")
	)
	(segment
		(start 394.859256 -60.463684)
		(end 388.26567 -67.05727)
		(width 0.127)
		(layer "In15.Cu")
		(net "FM_CPU_FBRK_DEBUG_R_N")
	)
	(segment
		(start 175.91532 -147.81149)
		(end 143.800068 -147.81149)
		(width 0.127)
		(layer "In15.Cu")
		(net "FM_CPU_FBRK_DEBUG_R_N")
	)
	(segment
		(start 202.530456 -147.193254)
		(end 190.670434 -147.193254)
		(width 0.127)
		(layer "In15.Cu")
		(net "FM_CPU_FBRK_DEBUG_R_N")
	)
	(segment
		(start 388.26567 -67.05727)
		(end 388.26567 -67.959224)
		(width 0.127)
		(layer "In15.Cu")
		(net "FM_CPU_FBRK_DEBUG_R_N")
	)
	(segment
		(start 335.42351 -113.9952)
		(end 331.40269 -115.660678)
		(width 0.127)
		(layer "In15.Cu")
		(net "FM_CPU_FBRK_DEBUG_R_N")
	)
	(segment
		(start 76.88707 -174.273718)
		(end 76.88707 -178.398678)
		(width 0.127)
		(layer "In15.Cu")
		(net "FM_CPU_FBRK_DEBUG_R_N")
	)
	(segment
		(start 66.792348 -181.541674)
		(end 57.489852 -181.541674)
		(width 0.127)
		(layer "In15.Cu")
		(net "FM_CPU_FBRK_DEBUG_R_N")
	)
	(segment
		(start 75.0062 -180.279548)
		(end 72.625458 -180.279548)
		(width 0.127)
		(layer "In15.Cu")
		(net "FM_CPU_FBRK_DEBUG_R_N")
	)
	(segment
		(start 101.873304 -146.109944)
		(end 101.749606 -146.109944)
		(width 0.127)
		(layer "In15.Cu")
		(net "FM_CPU_FBRK_DEBUG_R_N")
	)
	(segment
		(start 136.584182 -147.81149)
		(end 103.57485 -147.81149)
		(width 0.127)
		(layer "In15.Cu")
		(net "FM_CPU_FBRK_DEBUG_R_N")
	)
	(segment
		(start 190.670434 -147.193254)
		(end 187.70854 -150.155148)
		(width 0.127)
		(layer "In15.Cu")
		(net "FM_CPU_FBRK_DEBUG_R_N")
	)
	(segment
		(start 76.88707 -178.398678)
		(end 75.0062 -180.279548)
		(width 0.127)
		(layer "In15.Cu")
		(net "FM_CPU_FBRK_DEBUG_R_N")
	)
	(segment
		(start 376.72264 -113.9952)
		(end 335.42351 -113.9952)
		(width 0.127)
		(layer "In15.Cu")
		(net "FM_CPU_FBRK_DEBUG_R_N")
	)
	(segment
		(start 67.651122 -182.400448)
		(end 66.792348 -181.541674)
		(width 0.127)
		(layer "In15.Cu")
		(net "FM_CPU_FBRK_DEBUG_R_N")
	)
	(segment
		(start 70.504558 -182.400448)
		(end 67.651122 -182.400448)
		(width 0.127)
		(layer "In15.Cu")
		(net "FM_CPU_FBRK_DEBUG_R_N")
	)
	(segment
		(start 388.26567 -67.959224)
		(end 386.646674 -69.57822)
		(width 0.127)
		(layer "In15.Cu")
		(net "FM_CPU_FBRK_DEBUG_R_N")
	)
	(segment
		(start 142.227554 -146.238976)
		(end 138.156696 -146.238976)
		(width 0.127)
		(layer "In15.Cu")
		(net "FM_CPU_FBRK_DEBUG_R_N")
	)
	(segment
		(start 370.4082 -93.354398)
		(end 370.8146 -93.760798)
		(width 0.12954)
		(layer "F.Cu")
		(net "FM_CPU_FBRK_DEBUG_N")
	)
	(segment
		(start 403.606762 -55.253636)
		(end 402.917914 -54.564788)
		(width 0.12954)
		(layer "F.Cu")
		(net "FM_CPU_FBRK_DEBUG_N")
	)
	(segment
		(start 399.1356 -55.249826)
		(end 397.765016 -55.249826)
		(width 0.12954)
		(layer "F.Cu")
		(net "FM_CPU_FBRK_DEBUG_N")
	)
	(segment
		(start 399.820638 -54.564788)
		(end 399.1356 -55.249826)
		(width 0.12954)
		(layer "F.Cu")
		(net "FM_CPU_FBRK_DEBUG_N")
	)
	(segment
		(start 371.022372 -94.396814)
		(end 371.022372 -96.264984)
		(width 0.12954)
		(layer "F.Cu")
		(net "FM_CPU_FBRK_DEBUG_N")
	)
	(segment
		(start 370.8146 -94.189042)
		(end 371.022372 -94.396814)
		(width 0.12954)
		(layer "F.Cu")
		(net "FM_CPU_FBRK_DEBUG_N")
	)
	(segment
		(start 407.0604 -58.301128)
		(end 404.116286 -58.301128)
		(width 0.12954)
		(layer "F.Cu")
		(net "FM_CPU_FBRK_DEBUG_N")
	)
	(segment
		(start 403.606762 -55.759604)
		(end 403.606762 -55.253636)
		(width 0.12954)
		(layer "F.Cu")
		(net "FM_CPU_FBRK_DEBUG_N")
	)
	(segment
		(start 402.917914 -54.564788)
		(end 399.820638 -54.564788)
		(width 0.12954)
		(layer "F.Cu")
		(net "FM_CPU_FBRK_DEBUG_N")
	)
	(segment
		(start 370.8146 -93.760798)
		(end 370.8146 -94.189042)
		(width 0.12954)
		(layer "F.Cu")
		(net "FM_CPU_FBRK_DEBUG_N")
	)
	(segment
		(start 407.47696 -57.884568)
		(end 407.0604 -58.301128)
		(width 0.12954)
		(layer "F.Cu")
		(net "FM_CPU_FBRK_DEBUG_N")
	)
	(segment
		(start 404.116286 -58.301128)
		(end 403.606762 -57.791604)
		(width 0.12954)
		(layer "F.Cu")
		(net "FM_CPU_FBRK_DEBUG_N")
	)
	(segment
		(start 403.606762 -57.791604)
		(end 403.606762 -55.759604)
		(width 0.12954)
		(layer "F.Cu")
		(net "FM_CPU_FBRK_DEBUG_N")
	)
	(via
		(at 370.8146 -94.189042)
		(size 0.508)
		(drill 0.254)
		(layers "F.Cu" "B.Cu")
		(net "FM_CPU_FBRK_DEBUG_N")
	)
	(via
		(at 379.25248 -61.064648)
		(size 0.508)
		(drill 0.254)
		(layers "F.Cu" "B.Cu")
		(net "FM_CPU_FBRK_DEBUG_N")
	)
	(via
		(at 407.47696 -57.884568)
		(size 0.508)
		(drill 0.254)
		(layers "F.Cu" "B.Cu")
		(net "FM_CPU_FBRK_DEBUG_N")
	)
	(via
		(at 324.69328 -60.780168)
		(size 0.508)
		(drill 0.254)
		(layers "F.Cu" "B.Cu")
		(net "FM_CPU_FBRK_DEBUG_N")
	)
	(segment
		(start 323.1261 -60.914788)
		(end 322.601082 -60.38977)
		(width 0.12954)
		(layer "B.Cu")
		(net "FM_CPU_FBRK_DEBUG_N")
	)
	(segment
		(start 324.55866 -60.914788)
		(end 323.1261 -60.914788)
		(width 0.12954)
		(layer "B.Cu")
		(net "FM_CPU_FBRK_DEBUG_N")
	)
	(segment
		(start 324.69328 -60.780168)
		(end 324.55866 -60.914788)
		(width 0.12954)
		(layer "B.Cu")
		(net "FM_CPU_FBRK_DEBUG_N")
	)
	(segment
		(start 322.601082 -60.38977)
		(end 322.601082 -59.742324)
		(width 0.12954)
		(layer "B.Cu")
		(net "FM_CPU_FBRK_DEBUG_N")
	)
	(segment
		(start 382.04902 -62.410848)
		(end 380.70282 -61.064648)
		(width 0.127)
		(layer "In6.Cu")
		(net "FM_CPU_FBRK_DEBUG_N")
	)
	(segment
		(start 384.28168 -62.014608)
		(end 383.88544 -62.410848)
		(width 0.127)
		(layer "In6.Cu")
		(net "FM_CPU_FBRK_DEBUG_N")
	)
	(segment
		(start 383.88544 -62.410848)
		(end 382.04902 -62.410848)
		(width 0.127)
		(layer "In6.Cu")
		(net "FM_CPU_FBRK_DEBUG_N")
	)
	(segment
		(start 407.47696 -57.884568)
		(end 407.04262 -58.318908)
		(width 0.127)
		(layer "In6.Cu")
		(net "FM_CPU_FBRK_DEBUG_N")
	)
	(segment
		(start 407.04262 -58.318908)
		(end 397.6116 -58.318908)
		(width 0.127)
		(layer "In6.Cu")
		(net "FM_CPU_FBRK_DEBUG_N")
	)
	(segment
		(start 380.70282 -61.064648)
		(end 379.25248 -61.064648)
		(width 0.127)
		(layer "In6.Cu")
		(net "FM_CPU_FBRK_DEBUG_N")
	)
	(segment
		(start 397.6116 -58.318908)
		(end 393.9159 -62.014608)
		(width 0.127)
		(layer "In6.Cu")
		(net "FM_CPU_FBRK_DEBUG_N")
	)
	(segment
		(start 393.9159 -62.014608)
		(end 384.28168 -62.014608)
		(width 0.127)
		(layer "In6.Cu")
		(net "FM_CPU_FBRK_DEBUG_N")
	)
	(segment
		(start 371.495066 -94.189042)
		(end 372.67896 -93.005148)
		(width 0.127)
		(layer "In13.Cu")
		(net "FM_CPU_FBRK_DEBUG_N")
	)
	(segment
		(start 386.72516 -93.005148)
		(end 396.95882 -82.771488)
		(width 0.127)
		(layer "In13.Cu")
		(net "FM_CPU_FBRK_DEBUG_N")
	)
	(segment
		(start 396.95882 -72.868028)
		(end 402.93798 -66.888868)
		(width 0.127)
		(layer "In13.Cu")
		(net "FM_CPU_FBRK_DEBUG_N")
	)
	(segment
		(start 372.67896 -93.005148)
		(end 386.72516 -93.005148)
		(width 0.127)
		(layer "In13.Cu")
		(net "FM_CPU_FBRK_DEBUG_N")
	)
	(segment
		(start 396.95882 -82.771488)
		(end 396.95882 -72.868028)
		(width 0.127)
		(layer "In13.Cu")
		(net "FM_CPU_FBRK_DEBUG_N")
	)
	(segment
		(start 402.93798 -62.423548)
		(end 407.47696 -57.884568)
		(width 0.127)
		(layer "In13.Cu")
		(net "FM_CPU_FBRK_DEBUG_N")
	)
	(segment
		(start 402.93798 -66.888868)
		(end 402.93798 -62.423548)
		(width 0.127)
		(layer "In13.Cu")
		(net "FM_CPU_FBRK_DEBUG_N")
	)
	(segment
		(start 370.8146 -94.189042)
		(end 371.495066 -94.189042)
		(width 0.127)
		(layer "In13.Cu")
		(net "FM_CPU_FBRK_DEBUG_N")
	)
	(segment
		(start 371.50548 -61.064648)
		(end 370.70284 -61.867288)
		(width 0.127)
		(layer "In15.Cu")
		(net "FM_CPU_FBRK_DEBUG_N")
	)
	(segment
		(start 379.25248 -61.064648)
		(end 371.50548 -61.064648)
		(width 0.127)
		(layer "In15.Cu")
		(net "FM_CPU_FBRK_DEBUG_N")
	)
	(segment
		(start 344.55354 -58.933588)
		(end 328.60742 -58.933588)
		(width 0.127)
		(layer "In15.Cu")
		(net "FM_CPU_FBRK_DEBUG_N")
	)
	(segment
		(start 326.76084 -60.780168)
		(end 324.69328 -60.780168)
		(width 0.127)
		(layer "In15.Cu")
		(net "FM_CPU_FBRK_DEBUG_N")
	)
	(segment
		(start 352.80346 -59.433968)
		(end 345.05392 -59.433968)
		(width 0.127)
		(layer "In15.Cu")
		(net "FM_CPU_FBRK_DEBUG_N")
	)
	(segment
		(start 355.23678 -61.867288)
		(end 352.80346 -59.433968)
		(width 0.127)
		(layer "In15.Cu")
		(net "FM_CPU_FBRK_DEBUG_N")
	)
	(segment
		(start 370.70284 -61.867288)
		(end 355.23678 -61.867288)
		(width 0.127)
		(layer "In15.Cu")
		(net "FM_CPU_FBRK_DEBUG_N")
	)
	(segment
		(start 345.05392 -59.433968)
		(end 344.55354 -58.933588)
		(width 0.127)
		(layer "In15.Cu")
		(net "FM_CPU_FBRK_DEBUG_N")
	)
	(segment
		(start 328.60742 -58.933588)
		(end 326.76084 -60.780168)
		(width 0.127)
		(layer "In15.Cu")
		(net "FM_CPU_FBRK_DEBUG_N")
	)
	(via
		(at 210.04022 -191.097408)
		(size 0.6604)
		(drill 0.3302)
		(layers "F.Cu" "B.Cu")
		(net "FM_CPU_EN_R")
	)
	(segment
		(start 210.04022 -191.097408)
		(end 195.856606 -191.097408)
		(width 0.12954)
		(layer "B.Cu")
		(net "FM_CPU_EN_R")
	)
	(segment
		(start 215.134698 -193.168524)
		(end 215.134698 -191.82207)
		(width 0.12954)
		(layer "B.Cu")
		(net "FM_CPU_EN_R")
	)
	(segment
		(start 215.434164 -193.46799)
		(end 215.134698 -193.168524)
		(width 0.12954)
		(layer "B.Cu")
		(net "FM_CPU_EN_R")
	)
	(segment
		(start 215.134698 -191.82207)
		(end 214.410036 -191.097408)
		(width 0.12954)
		(layer "B.Cu")
		(net "FM_CPU_EN_R")
	)
	(segment
		(start 215.761316 -193.46799)
		(end 215.434164 -193.46799)
		(width 0.12954)
		(layer "B.Cu")
		(net "FM_CPU_EN_R")
	)
	(segment
		(start 195.856606 -191.097408)
		(end 195.646548 -191.307466)
		(width 0.12954)
		(layer "B.Cu")
		(net "FM_CPU_EN_R")
	)
	(segment
		(start 214.410036 -191.097408)
		(end 210.04022 -191.097408)
		(width 0.12954)
		(layer "B.Cu")
		(net "FM_CPU_EN_R")
	)
	(via
		(at 193.69278 -192.037208)
		(size 0.6604)
		(drill 0.3302)
		(layers "F.Cu" "B.Cu")
		(net "FM_CPU_EN")
	)
	(segment
		(start 194.422522 -191.307466)
		(end 194.846448 -191.307466)
		(width 0.12954)
		(layer "B.Cu")
		(net "FM_CPU_EN")
	)
	(segment
		(start 196.017896 -192.617598)
		(end 196.013578 -192.621916)
		(width 0.12954)
		(layer "B.Cu")
		(net "FM_CPU_EN")
	)
	(segment
		(start 194.277488 -192.621916)
		(end 193.69278 -192.037208)
		(width 0.12954)
		(layer "B.Cu")
		(net "FM_CPU_EN")
	)
	(segment
		(start 196.013578 -192.621916)
		(end 194.277488 -192.621916)
		(width 0.12954)
		(layer "B.Cu")
		(net "FM_CPU_EN")
	)
	(segment
		(start 193.69278 -192.037208)
		(end 194.422522 -191.307466)
		(width 0.12954)
		(layer "B.Cu")
		(net "FM_CPU_EN")
	)
	(segment
		(start 213.001098 -194.77355)
		(end 212.480398 -194.25285)
		(width 0.12954)
		(layer "F.Cu")
		(net "FM_CPU1_SKTOCC_N")
	)
	(segment
		(start 203.4286 -192.77203)
		(end 200.392792 -192.77203)
		(width 0.12954)
		(layer "F.Cu")
		(net "FM_CPU1_SKTOCC_N")
	)
	(segment
		(start 199.429878 -193.855848)
		(end 198.75881 -194.526916)
		(width 0.12954)
		(layer "F.Cu")
		(net "FM_CPU1_SKTOCC_N")
	)
	(segment
		(start 198.75881 -194.526916)
		(end 198.75881 -194.742308)
		(width 0.12954)
		(layer "F.Cu")
		(net "FM_CPU1_SKTOCC_N")
	)
	(segment
		(start 212.216238 -194.25285)
		(end 212.129878 -194.16649)
		(width 0.12954)
		(layer "F.Cu")
		(net "FM_CPU1_SKTOCC_N")
	)
	(segment
		(start 212.480398 -194.25285)
		(end 212.216238 -194.25285)
		(width 0.12954)
		(layer "F.Cu")
		(net "FM_CPU1_SKTOCC_N")
	)
	(segment
		(start 200.392792 -192.77203)
		(end 199.429878 -193.734944)
		(width 0.12954)
		(layer "F.Cu")
		(net "FM_CPU1_SKTOCC_N")
	)
	(segment
		(start 204.398118 -193.741548)
		(end 203.4286 -192.77203)
		(width 0.12954)
		(layer "F.Cu")
		(net "FM_CPU1_SKTOCC_N")
	)
	(segment
		(start 212.129878 -194.16649)
		(end 208.711038 -194.16649)
		(width 0.12954)
		(layer "F.Cu")
		(net "FM_CPU1_SKTOCC_N")
	)
	(segment
		(start 199.429878 -193.734944)
		(end 199.429878 -193.855848)
		(width 0.12954)
		(layer "F.Cu")
		(net "FM_CPU1_SKTOCC_N")
	)
	(segment
		(start 207.316578 -192.77203)
		(end 206.734664 -192.77203)
		(width 0.12954)
		(layer "F.Cu")
		(net "FM_CPU1_SKTOCC_N")
	)
	(segment
		(start 205.765146 -193.741548)
		(end 204.398118 -193.741548)
		(width 0.12954)
		(layer "F.Cu")
		(net "FM_CPU1_SKTOCC_N")
	)
	(segment
		(start 208.711038 -194.16649)
		(end 207.316578 -192.77203)
		(width 0.12954)
		(layer "F.Cu")
		(net "FM_CPU1_SKTOCC_N")
	)
	(segment
		(start 206.734664 -192.77203)
		(end 205.765146 -193.741548)
		(width 0.12954)
		(layer "F.Cu")
		(net "FM_CPU1_SKTOCC_N")
	)
	(via
		(at 213.001098 -194.77355)
		(size 0.508)
		(drill 0.254)
		(layers "F.Cu" "B.Cu")
		(net "FM_CPU1_SKTOCC_N")
	)
	(via
		(at 211.919058 -195.39839)
		(size 0.6604)
		(drill 0.3302)
		(layers "F.Cu" "B.Cu")
		(net "FM_CPU1_SKTOCC_N")
	)
	(via
		(at 198.75881 -194.742308)
		(size 0.508)
		(drill 0.254)
		(layers "F.Cu" "B.Cu")
		(net "FM_CPU1_SKTOCC_N")
	)
	(segment
		(start 198.75881 -194.742308)
		(end 198.462138 -194.445636)
		(width 0.12954)
		(layer "B.Cu")
		(net "FM_CPU1_SKTOCC_N")
	)
	(segment
		(start 199.06869 -194.148964)
		(end 199.06869 -194.432428)
		(width 0.12954)
		(layer "B.Cu")
		(net "FM_CPU1_SKTOCC_N")
	)
	(segment
		(start 211.367878 -195.26885)
		(end 211.367878 -194.70497)
		(width 0.12954)
		(layer "B.Cu")
		(net "FM_CPU1_SKTOCC_N")
	)
	(segment
		(start 211.919058 -195.39839)
		(end 211.497418 -195.39839)
		(width 0.12954)
		(layer "B.Cu")
		(net "FM_CPU1_SKTOCC_N")
	)
	(segment
		(start 211.367878 -194.70497)
		(end 211.61248 -194.460368)
		(width 0.12954)
		(layer "B.Cu")
		(net "FM_CPU1_SKTOCC_N")
	)
	(segment
		(start 213.001098 -194.77355)
		(end 212.543898 -194.77355)
		(width 0.12954)
		(layer "B.Cu")
		(net "FM_CPU1_SKTOCC_N")
	)
	(segment
		(start 199.198484 -194.01917)
		(end 199.06869 -194.148964)
		(width 0.12954)
		(layer "B.Cu")
		(net "FM_CPU1_SKTOCC_N")
	)
	(segment
		(start 211.497418 -195.39839)
		(end 211.367878 -195.26885)
		(width 0.12954)
		(layer "B.Cu")
		(net "FM_CPU1_SKTOCC_N")
	)
	(segment
		(start 212.543898 -194.77355)
		(end 211.919058 -195.39839)
		(width 0.12954)
		(layer "B.Cu")
		(net "FM_CPU1_SKTOCC_N")
	)
	(segment
		(start 199.631808 -194.01917)
		(end 200.355708 -194.74307)
		(width 0.12954)
		(layer "B.Cu")
		(net "FM_CPU1_SKTOCC_N")
	)
	(segment
		(start 200.355708 -194.74307)
		(end 200.87336 -194.74307)
		(width 0.12954)
		(layer "B.Cu")
		(net "FM_CPU1_SKTOCC_N")
	)
	(segment
		(start 198.119492 -193.91757)
		(end 197.795896 -193.91757)
		(width 0.12954)
		(layer "B.Cu")
		(net "FM_CPU1_SKTOCC_N")
	)
	(segment
		(start 199.06869 -194.432428)
		(end 198.75881 -194.742308)
		(width 0.12954)
		(layer "B.Cu")
		(net "FM_CPU1_SKTOCC_N")
	)
	(segment
		(start 198.462138 -194.260216)
		(end 198.119492 -193.91757)
		(width 0.12954)
		(layer "B.Cu")
		(net "FM_CPU1_SKTOCC_N")
	)
	(segment
		(start 211.61248 -194.460368)
		(end 211.61248 -194.079876)
		(width 0.12954)
		(layer "B.Cu")
		(net "FM_CPU1_SKTOCC_N")
	)
	(segment
		(start 200.87336 -194.74307)
		(end 201.561446 -194.054984)
		(width 0.12954)
		(layer "B.Cu")
		(net "FM_CPU1_SKTOCC_N")
	)
	(segment
		(start 198.462138 -194.445636)
		(end 198.462138 -194.260216)
		(width 0.12954)
		(layer "B.Cu")
		(net "FM_CPU1_SKTOCC_N")
	)
	(segment
		(start 199.631808 -194.01917)
		(end 199.198484 -194.01917)
		(width 0.12954)
		(layer "B.Cu")
		(net "FM_CPU1_SKTOCC_N")
	)
	(segment
		(start 179.755546 -116.975382)
		(end 180.155596 -117.375432)
		(width 0.12954)
		(layer "F.Cu")
		(net "FM_CPU1_SKTOCC_LVT3_PLD_N")
	)
	(segment
		(start 179.12588 -133.295898)
		(end 178.246278 -132.416296)
		(width 0.12954)
		(layer "F.Cu")
		(net "FM_CPU1_SKTOCC_LVT3_PLD_N")
	)
	(via
		(at 178.246278 -132.416296)
		(size 0.508)
		(drill 0.254)
		(layers "F.Cu" "B.Cu")
		(net "FM_CPU1_SKTOCC_LVT3_PLD_N")
	)
	(via
		(at 180.155596 -117.375432)
		(size 0.4572)
		(drill 0.254)
		(layers "F.Cu" "B.Cu")
		(net "FM_CPU1_SKTOCC_LVT3_PLD_N")
	)
	(segment
		(start 178.421792 -122.385582)
		(end 178.421792 -121.407936)
		(width 0.12954)
		(layer "B.Cu")
		(net "FM_CPU1_SKTOCC_LVT3_PLD_N")
	)
	(segment
		(start 177.60188 -131.771898)
		(end 177.60188 -123.205494)
		(width 0.12954)
		(layer "B.Cu")
		(net "FM_CPU1_SKTOCC_LVT3_PLD_N")
	)
	(segment
		(start 179.75326 -117.777768)
		(end 180.155596 -117.375432)
		(width 0.12954)
		(layer "B.Cu")
		(net "FM_CPU1_SKTOCC_LVT3_PLD_N")
	)
	(segment
		(start 177.60188 -123.205494)
		(end 178.421792 -122.385582)
		(width 0.12954)
		(layer "B.Cu")
		(net "FM_CPU1_SKTOCC_LVT3_PLD_N")
	)
	(segment
		(start 178.246278 -132.416296)
		(end 177.60188 -131.771898)
		(width 0.12954)
		(layer "B.Cu")
		(net "FM_CPU1_SKTOCC_LVT3_PLD_N")
	)
	(segment
		(start 179.75326 -120.076468)
		(end 179.75326 -117.777768)
		(width 0.12954)
		(layer "B.Cu")
		(net "FM_CPU1_SKTOCC_LVT3_PLD_N")
	)
	(segment
		(start 178.421792 -121.407936)
		(end 179.75326 -120.076468)
		(width 0.12954)
		(layer "B.Cu")
		(net "FM_CPU1_SKTOCC_LVT3_PLD_N")
	)
	(segment
		(start 115.979448 -269.383256)
		(end 115.979194 -269.38351)
		(width 0.12954)
		(layer "F.Cu")
		(net "FM_CPU1_SKTOCC_LVT3_N")
	)
	(segment
		(start 179.12588 -134.095998)
		(end 179.12588 -134.711948)
		(width 0.12954)
		(layer "F.Cu")
		(net "FM_CPU1_SKTOCC_LVT3_N")
	)
	(segment
		(start 115.979448 -268.84757)
		(end 115.979448 -269.383256)
		(width 0.12954)
		(layer "F.Cu")
		(net "FM_CPU1_SKTOCC_LVT3_N")
	)
	(via
		(at 201.715878 -193.36893)
		(size 0.508)
		(drill 0.254)
		(layers "F.Cu" "B.Cu")
		(net "FM_CPU1_SKTOCC_LVT3_N")
	)
	(via
		(at 183.057038 -194.528948)
		(size 0.508)
		(drill 0.254)
		(layers "F.Cu" "B.Cu")
		(net "FM_CPU1_SKTOCC_LVT3_N")
	)
	(via
		(at 194.49288 -134.711948)
		(size 0.508)
		(drill 0.254)
		(layers "F.Cu" "B.Cu")
		(net "FM_CPU1_SKTOCC_LVT3_N")
	)
	(via
		(at 179.12588 -134.711948)
		(size 0.508)
		(drill 0.254)
		(layers "F.Cu" "B.Cu")
		(net "FM_CPU1_SKTOCC_LVT3_N")
	)
	(via
		(at 115.979194 -269.38351)
		(size 0.4572)
		(drill 0.2032)
		(layers "F.Cu" "B.Cu")
		(net "FM_CPU1_SKTOCC_LVT3_N")
	)
	(via
		(at 155.528518 -271.49933)
		(size 0.6604)
		(drill 0.3302)
		(layers "F.Cu" "B.Cu")
		(net "FM_CPU1_SKTOCC_LVT3_N")
	)
	(segment
		(start 157.522418 -272.96745)
		(end 156.054298 -271.49933)
		(width 0.12954)
		(layer "B.Cu")
		(net "FM_CPU1_SKTOCC_LVT3_N")
	)
	(segment
		(start 165.010338 -272.75663)
		(end 164.659818 -272.40611)
		(width 0.12954)
		(layer "B.Cu")
		(net "FM_CPU1_SKTOCC_LVT3_N")
	)
	(segment
		(start 140.255498 -270.25981)
		(end 140.016738 -270.02105)
		(width 0.12954)
		(layer "B.Cu")
		(net "FM_CPU1_SKTOCC_LVT3_N")
	)
	(segment
		(start 116.704618 -269.79499)
		(end 116.293138 -269.38351)
		(width 0.12954)
		(layer "B.Cu")
		(net "FM_CPU1_SKTOCC_LVT3_N")
	)
	(segment
		(start 116.293138 -269.38351)
		(end 115.979194 -269.38351)
		(width 0.12954)
		(layer "B.Cu")
		(net "FM_CPU1_SKTOCC_LVT3_N")
	)
	(segment
		(start 172.244258 -258.40817)
		(end 172.244258 -269.56893)
		(width 0.12954)
		(layer "B.Cu")
		(net "FM_CPU1_SKTOCC_LVT3_N")
	)
	(segment
		(start 171.149518 -270.14043)
		(end 168.533318 -272.75663)
		(width 0.12954)
		(layer "B.Cu")
		(net "FM_CPU1_SKTOCC_LVT3_N")
	)
	(segment
		(start 201.715878 -193.36893)
		(end 201.715878 -193.44005)
		(width 0.12954)
		(layer "B.Cu")
		(net "FM_CPU1_SKTOCC_LVT3_N")
	)
	(segment
		(start 152.013158 -270.25981)
		(end 140.255498 -270.25981)
		(width 0.12954)
		(layer "B.Cu")
		(net "FM_CPU1_SKTOCC_LVT3_N")
	)
	(segment
		(start 181.599078 -255.97485)
		(end 179.511198 -258.06273)
		(width 0.12954)
		(layer "B.Cu")
		(net "FM_CPU1_SKTOCC_LVT3_N")
	)
	(segment
		(start 137.022078 -269.79499)
		(end 116.704618 -269.79499)
		(width 0.12954)
		(layer "B.Cu")
		(net "FM_CPU1_SKTOCC_LVT3_N")
	)
	(segment
		(start 155.528518 -271.49933)
		(end 153.252678 -271.49933)
		(width 0.12954)
		(layer "B.Cu")
		(net "FM_CPU1_SKTOCC_LVT3_N")
	)
	(segment
		(start 181.599078 -253.47041)
		(end 181.599078 -255.97485)
		(width 0.12954)
		(layer "B.Cu")
		(net "FM_CPU1_SKTOCC_LVT3_N")
	)
	(segment
		(start 179.511198 -258.06273)
		(end 172.589698 -258.06273)
		(width 0.12954)
		(layer "B.Cu")
		(net "FM_CPU1_SKTOCC_LVT3_N")
	)
	(segment
		(start 156.054298 -271.49933)
		(end 155.528518 -271.49933)
		(width 0.12954)
		(layer "B.Cu")
		(net "FM_CPU1_SKTOCC_LVT3_N")
	)
	(segment
		(start 161.126678 -272.40611)
		(end 160.565338 -272.96745)
		(width 0.12954)
		(layer "B.Cu")
		(net "FM_CPU1_SKTOCC_LVT3_N")
	)
	(segment
		(start 168.533318 -272.75663)
		(end 165.010338 -272.75663)
		(width 0.12954)
		(layer "B.Cu")
		(net "FM_CPU1_SKTOCC_LVT3_N")
	)
	(segment
		(start 153.252678 -271.49933)
		(end 152.013158 -270.25981)
		(width 0.12954)
		(layer "B.Cu")
		(net "FM_CPU1_SKTOCC_LVT3_N")
	)
	(segment
		(start 201.715878 -193.44005)
		(end 202.330812 -194.054984)
		(width 0.12954)
		(layer "B.Cu")
		(net "FM_CPU1_SKTOCC_LVT3_N")
	)
	(segment
		(start 164.659818 -272.40611)
		(end 161.126678 -272.40611)
		(width 0.12954)
		(layer "B.Cu")
		(net "FM_CPU1_SKTOCC_LVT3_N")
	)
	(segment
		(start 172.244258 -269.56893)
		(end 171.672758 -270.14043)
		(width 0.12954)
		(layer "B.Cu")
		(net "FM_CPU1_SKTOCC_LVT3_N")
	)
	(segment
		(start 183.057038 -252.01245)
		(end 181.599078 -253.47041)
		(width 0.12954)
		(layer "B.Cu")
		(net "FM_CPU1_SKTOCC_LVT3_N")
	)
	(segment
		(start 172.589698 -258.06273)
		(end 172.244258 -258.40817)
		(width 0.12954)
		(layer "B.Cu")
		(net "FM_CPU1_SKTOCC_LVT3_N")
	)
	(segment
		(start 171.672758 -270.14043)
		(end 171.149518 -270.14043)
		(width 0.12954)
		(layer "B.Cu")
		(net "FM_CPU1_SKTOCC_LVT3_N")
	)
	(segment
		(start 202.330812 -194.054984)
		(end 202.361546 -194.054984)
		(width 0.12954)
		(layer "B.Cu")
		(net "FM_CPU1_SKTOCC_LVT3_N")
	)
	(segment
		(start 137.248138 -270.02105)
		(end 137.022078 -269.79499)
		(width 0.12954)
		(layer "B.Cu")
		(net "FM_CPU1_SKTOCC_LVT3_N")
	)
	(segment
		(start 140.016738 -270.02105)
		(end 137.248138 -270.02105)
		(width 0.12954)
		(layer "B.Cu")
		(net "FM_CPU1_SKTOCC_LVT3_N")
	)
	(segment
		(start 160.565338 -272.96745)
		(end 157.522418 -272.96745)
		(width 0.12954)
		(layer "B.Cu")
		(net "FM_CPU1_SKTOCC_LVT3_N")
	)
	(segment
		(start 183.057038 -194.528948)
		(end 183.057038 -252.01245)
		(width 0.12954)
		(layer "B.Cu")
		(net "FM_CPU1_SKTOCC_LVT3_N")
	)
	(segment
		(start 209.544158 -164.428424)
		(end 209.80908 -164.163502)
		(width 0.127)
		(layer "In2.Cu")
		(net "FM_CPU1_SKTOCC_LVT3_N")
	)
	(segment
		(start 201.715878 -192.804542)
		(end 203.019406 -189.65672)
		(width 0.127)
		(layer "In2.Cu")
		(net "FM_CPU1_SKTOCC_LVT3_N")
	)
	(segment
		(start 196.046344 -136.794748)
		(end 194.49288 -135.241284)
		(width 0.127)
		(layer "In2.Cu")
		(net "FM_CPU1_SKTOCC_LVT3_N")
	)
	(segment
		(start 209.544158 -181.24043)
		(end 209.544158 -164.428424)
		(width 0.127)
		(layer "In2.Cu")
		(net "FM_CPU1_SKTOCC_LVT3_N")
	)
	(segment
		(start 197.056756 -136.794748)
		(end 196.046344 -136.794748)
		(width 0.127)
		(layer "In2.Cu")
		(net "FM_CPU1_SKTOCC_LVT3_N")
	)
	(segment
		(start 201.715878 -193.36893)
		(end 201.715878 -192.804542)
		(width 0.127)
		(layer "In2.Cu")
		(net "FM_CPU1_SKTOCC_LVT3_N")
	)
	(segment
		(start 209.047334 -148.785326)
		(end 197.056756 -136.794748)
		(width 0.127)
		(layer "In2.Cu")
		(net "FM_CPU1_SKTOCC_LVT3_N")
	)
	(segment
		(start 209.80908 -150.62454)
		(end 209.047334 -148.785326)
		(width 0.127)
		(layer "In2.Cu")
		(net "FM_CPU1_SKTOCC_LVT3_N")
	)
	(segment
		(start 203.019406 -189.65672)
		(end 203.019406 -187.765182)
		(width 0.127)
		(layer "In2.Cu")
		(net "FM_CPU1_SKTOCC_LVT3_N")
	)
	(segment
		(start 209.80908 -164.163502)
		(end 209.80908 -150.62454)
		(width 0.127)
		(layer "In2.Cu")
		(net "FM_CPU1_SKTOCC_LVT3_N")
	)
	(segment
		(start 203.019406 -187.765182)
		(end 209.544158 -181.24043)
		(width 0.127)
		(layer "In2.Cu")
		(net "FM_CPU1_SKTOCC_LVT3_N")
	)
	(segment
		(start 194.49288 -135.241284)
		(end 194.49288 -134.711948)
		(width 0.127)
		(layer "In2.Cu")
		(net "FM_CPU1_SKTOCC_LVT3_N")
	)
	(segment
		(start 194.87388 -193.893948)
		(end 194.36588 -193.385948)
		(width 0.127)
		(layer "In4.Cu")
		(net "FM_CPU1_SKTOCC_LVT3_N")
	)
	(segment
		(start 196.39788 -193.512948)
		(end 196.01688 -193.893948)
		(width 0.127)
		(layer "In4.Cu")
		(net "FM_CPU1_SKTOCC_LVT3_N")
	)
	(segment
		(start 201.224896 -192.877948)
		(end 198.68388 -192.877948)
		(width 0.127)
		(layer "In4.Cu")
		(net "FM_CPU1_SKTOCC_LVT3_N")
	)
	(segment
		(start 198.04888 -193.512948)
		(end 196.39788 -193.512948)
		(width 0.127)
		(layer "In4.Cu")
		(net "FM_CPU1_SKTOCC_LVT3_N")
	)
	(segment
		(start 196.01688 -193.893948)
		(end 194.87388 -193.893948)
		(width 0.127)
		(layer "In4.Cu")
		(net "FM_CPU1_SKTOCC_LVT3_N")
	)
	(segment
		(start 184.200038 -193.385948)
		(end 183.057038 -194.528948)
		(width 0.127)
		(layer "In4.Cu")
		(net "FM_CPU1_SKTOCC_LVT3_N")
	)
	(segment
		(start 198.68388 -192.877948)
		(end 198.04888 -193.512948)
		(width 0.127)
		(layer "In4.Cu")
		(net "FM_CPU1_SKTOCC_LVT3_N")
	)
	(segment
		(start 201.715878 -193.36893)
		(end 201.224896 -192.877948)
		(width 0.127)
		(layer "In4.Cu")
		(net "FM_CPU1_SKTOCC_LVT3_N")
	)
	(segment
		(start 194.36588 -193.385948)
		(end 184.200038 -193.385948)
		(width 0.127)
		(layer "In4.Cu")
		(net "FM_CPU1_SKTOCC_LVT3_N")
	)
	(segment
		(start 179.953412 -135.53948)
		(end 189.04712 -135.53948)
		(width 0.127)
		(layer "In15.Cu")
		(net "FM_CPU1_SKTOCC_LVT3_N")
	)
	(segment
		(start 189.04712 -135.53948)
		(end 189.366652 -135.219948)
		(width 0.127)
		(layer "In15.Cu")
		(net "FM_CPU1_SKTOCC_LVT3_N")
	)
	(segment
		(start 179.12588 -134.711948)
		(end 179.953412 -135.53948)
		(width 0.127)
		(layer "In15.Cu")
		(net "FM_CPU1_SKTOCC_LVT3_N")
	)
	(segment
		(start 189.366652 -135.219948)
		(end 193.98488 -135.219948)
		(width 0.127)
		(layer "In15.Cu")
		(net "FM_CPU1_SKTOCC_LVT3_N")
	)
	(segment
		(start 193.98488 -135.219948)
		(end 194.49288 -134.711948)
		(width 0.127)
		(layer "In15.Cu")
		(net "FM_CPU1_SKTOCC_LVT3_N")
	)
	(segment
		(start 180.555646 -120.975374)
		(end 180.95468 -121.374408)
		(width 0.12954)
		(layer "F.Cu")
		(net "FM_CPU1_PROC_ID1")
	)
	(segment
		(start 180.82768 -124.576586)
		(end 181.592474 -125.34138)
		(width 0.12954)
		(layer "F.Cu")
		(net "FM_CPU1_PROC_ID1")
	)
	(segment
		(start 182.165498 -125.34138)
		(end 182.165498 -125.914404)
		(width 0.12954)
		(layer "F.Cu")
		(net "FM_CPU1_PROC_ID1")
	)
	(segment
		(start 107.051094 -272.917158)
		(end 107.051348 -272.917412)
		(width 0.12954)
		(layer "F.Cu")
		(net "FM_CPU1_PROC_ID1")
	)
	(segment
		(start 182.61965 -126.564898)
		(end 182.17388 -126.564898)
		(width 0.12954)
		(layer "F.Cu")
		(net "FM_CPU1_PROC_ID1")
	)
	(segment
		(start 182.88762 -131.712208)
		(end 182.88762 -126.832868)
		(width 0.12954)
		(layer "F.Cu")
		(net "FM_CPU1_PROC_ID1")
	)
	(segment
		(start 182.165498 -125.914404)
		(end 182.17388 -125.922786)
		(width 0.12954)
		(layer "F.Cu")
		(net "FM_CPU1_PROC_ID1")
	)
	(segment
		(start 180.95468 -122.113548)
		(end 180.82768 -122.240548)
		(width 0.12954)
		(layer "F.Cu")
		(net "FM_CPU1_PROC_ID1")
	)
	(segment
		(start 182.17388 -125.922786)
		(end 182.17388 -126.564898)
		(width 0.12954)
		(layer "F.Cu")
		(net "FM_CPU1_PROC_ID1")
	)
	(segment
		(start 107.051348 -272.917412)
		(end 107.051348 -273.453098)
		(width 0.12954)
		(layer "F.Cu")
		(net "FM_CPU1_PROC_ID1")
	)
	(segment
		(start 182.88762 -126.832868)
		(end 182.61965 -126.564898)
		(width 0.12954)
		(layer "F.Cu")
		(net "FM_CPU1_PROC_ID1")
	)
	(segment
		(start 181.592474 -125.34138)
		(end 182.165498 -125.34138)
		(width 0.12954)
		(layer "F.Cu")
		(net "FM_CPU1_PROC_ID1")
	)
	(segment
		(start 182.17388 -132.425948)
		(end 182.88762 -131.712208)
		(width 0.12954)
		(layer "F.Cu")
		(net "FM_CPU1_PROC_ID1")
	)
	(segment
		(start 180.95468 -121.374408)
		(end 180.95468 -122.113548)
		(width 0.12954)
		(layer "F.Cu")
		(net "FM_CPU1_PROC_ID1")
	)
	(segment
		(start 180.82768 -122.240548)
		(end 180.82768 -124.576586)
		(width 0.12954)
		(layer "F.Cu")
		(net "FM_CPU1_PROC_ID1")
	)
	(via
		(at 182.17388 -132.425948)
		(size 0.508)
		(drill 0.254)
		(layers "F.Cu" "B.Cu")
		(net "FM_CPU1_PROC_ID1")
	)
	(via
		(at 182.165498 -125.34138)
		(size 0.762)
		(drill 0.381)
		(layers "F.Cu" "B.Cu")
		(net "FM_CPU1_PROC_ID1")
	)
	(via
		(at 51.72964 -185.877708)
		(size 0.508)
		(drill 0.254)
		(layers "F.Cu" "B.Cu")
		(net "FM_CPU1_PROC_ID1")
	)
	(via
		(at 107.051348 -273.453098)
		(size 0.4572)
		(drill 0.2032)
		(layers "F.Cu" "B.Cu")
		(net "FM_CPU1_PROC_ID1")
	)
	(via
		(at 67.687444 -263.84885)
		(size 0.6604)
		(drill 0.3302)
		(layers "F.Cu" "B.Cu")
		(net "FM_CPU1_PROC_ID1")
	)
	(segment
		(start 40.532558 -247.63603)
		(end 40.532558 -194.355974)
		(width 0.12954)
		(layer "B.Cu")
		(net "FM_CPU1_PROC_ID1")
	)
	(segment
		(start 106.313478 -273.76882)
		(end 106.298746 -273.777456)
		(width 0.0889)
		(layer "B.Cu")
		(net "FM_CPU1_PROC_ID1")
	)
	(segment
		(start 50.042064 -190.637668)
		(end 51.6382 -189.041532)
		(width 0.12954)
		(layer "B.Cu")
		(net "FM_CPU1_PROC_ID1")
	)
	(segment
		(start 107.051348 -273.453098)
		(end 106.894884 -273.724116)
		(width 0.0889)
		(layer "B.Cu")
		(net "FM_CPU1_PROC_ID1")
	)
	(segment
		(start 52.013358 -257.48361)
		(end 46.890178 -257.48361)
		(width 0.12954)
		(layer "B.Cu")
		(net "FM_CPU1_PROC_ID1")
	)
	(segment
		(start 62.767464 -264.27049)
		(end 59.194192 -264.27049)
		(width 0.12954)
		(layer "B.Cu")
		(net "FM_CPU1_PROC_ID1")
	)
	(segment
		(start 103.018082 -274.586192)
		(end 103.009192 -274.591272)
		(width 0.0889)
		(layer "B.Cu")
		(net "FM_CPU1_PROC_ID1")
	)
	(segment
		(start 91.35745 -274.591272)
		(end 91.347036 -274.585176)
		(width 0.0889)
		(layer "B.Cu")
		(net "FM_CPU1_PROC_ID1")
	)
	(segment
		(start 84.784438 -274.514564)
		(end 84.538312 -274.76069)
		(width 0.12954)
		(layer "B.Cu")
		(net "FM_CPU1_PROC_ID1")
	)
	(segment
		(start 100.755196 -274.591272)
		(end 100.740464 -274.582636)
		(width 0.0889)
		(layer "B.Cu")
		(net "FM_CPU1_PROC_ID1")
	)
	(segment
		(start 40.532558 -194.355974)
		(end 44.250864 -190.637668)
		(width 0.12954)
		(layer "B.Cu")
		(net "FM_CPU1_PROC_ID1")
	)
	(segment
		(start 105.373678 -273.76882)
		(end 105.358946 -273.777456)
		(width 0.0889)
		(layer "B.Cu")
		(net "FM_CPU1_PROC_ID1")
	)
	(segment
		(start 52.782978 -258.25323)
		(end 52.013358 -257.48361)
		(width 0.12954)
		(layer "B.Cu")
		(net "FM_CPU1_PROC_ID1")
	)
	(segment
		(start 87.047324 -274.582636)
		(end 87.032592 -274.591272)
		(width 0.0889)
		(layer "B.Cu")
		(net "FM_CPU1_PROC_ID1")
	)
	(segment
		(start 96.995996 -274.591272)
		(end 96.981264 -274.582636)
		(width 0.0889)
		(layer "B.Cu")
		(net "FM_CPU1_PROC_ID1")
	)
	(segment
		(start 55.767732 -263.89711)
		(end 52.782978 -260.912356)
		(width 0.12954)
		(layer "B.Cu")
		(net "FM_CPU1_PROC_ID1")
	)
	(segment
		(start 101.694996 -274.591272)
		(end 101.680264 -274.582636)
		(width 0.0889)
		(layer "B.Cu")
		(net "FM_CPU1_PROC_ID1")
	)
	(segment
		(start 93.236796 -274.591272)
		(end 93.222064 -274.582636)
		(width 0.0889)
		(layer "B.Cu")
		(net "FM_CPU1_PROC_ID1")
	)
	(segment
		(start 96.056196 -274.591272)
		(end 96.041464 -274.582636)
		(width 0.0889)
		(layer "B.Cu")
		(net "FM_CPU1_PROC_ID1")
	)
	(segment
		(start 78.972664 -274.76069)
		(end 68.060824 -263.84885)
		(width 0.12954)
		(layer "B.Cu")
		(net "FM_CPU1_PROC_ID1")
	)
	(segment
		(start 42.088308 -249.19178)
		(end 40.532558 -247.63603)
		(width 0.12954)
		(layer "B.Cu")
		(net "FM_CPU1_PROC_ID1")
	)
	(segment
		(start 103.489506 -273.77136)
		(end 103.479092 -273.777456)
		(width 0.0889)
		(layer "B.Cu")
		(net "FM_CPU1_PROC_ID1")
	)
	(segment
		(start 97.935796 -274.591272)
		(end 97.921064 -274.582636)
		(width 0.0889)
		(layer "B.Cu")
		(net "FM_CPU1_PROC_ID1")
	)
	(segment
		(start 85.432646 -274.514564)
		(end 84.990178 -274.514564)
		(width 0.0889)
		(layer "B.Cu")
		(net "FM_CPU1_PROC_ID1")
	)
	(segment
		(start 51.6382 -189.041532)
		(end 51.6382 -185.969148)
		(width 0.12954)
		(layer "B.Cu")
		(net "FM_CPU1_PROC_ID1")
	)
	(segment
		(start 102.634796 -274.591272)
		(end 102.620064 -274.582636)
		(width 0.0889)
		(layer "B.Cu")
		(net "FM_CPU1_PROC_ID1")
	)
	(segment
		(start 85.717888 -274.591272)
		(end 85.703156 -274.582636)
		(width 0.0889)
		(layer "B.Cu")
		(net "FM_CPU1_PROC_ID1")
	)
	(segment
		(start 59.194192 -264.27049)
		(end 58.820812 -263.89711)
		(width 0.12954)
		(layer "B.Cu")
		(net "FM_CPU1_PROC_ID1")
	)
	(segment
		(start 84.538312 -274.76069)
		(end 78.972664 -274.76069)
		(width 0.12954)
		(layer "B.Cu")
		(net "FM_CPU1_PROC_ID1")
	)
	(segment
		(start 104.433878 -273.76882)
		(end 104.419146 -273.777456)
		(width 0.0889)
		(layer "B.Cu")
		(net "FM_CPU1_PROC_ID1")
	)
	(segment
		(start 94.176596 -274.591272)
		(end 94.161864 -274.582636)
		(width 0.0889)
		(layer "B.Cu")
		(net "FM_CPU1_PROC_ID1")
	)
	(segment
		(start 106.894884 -273.724116)
		(end 106.80573 -273.747992)
		(width 0.0889)
		(layer "B.Cu")
		(net "FM_CPU1_PROC_ID1")
	)
	(segment
		(start 51.6382 -185.969148)
		(end 51.72964 -185.877708)
		(width 0.12954)
		(layer "B.Cu")
		(net "FM_CPU1_PROC_ID1")
	)
	(segment
		(start 84.990178 -274.514564)
		(end 84.784438 -274.514564)
		(width 0.12954)
		(layer "B.Cu")
		(net "FM_CPU1_PROC_ID1")
	)
	(segment
		(start 44.250864 -190.637668)
		(end 50.042064 -190.637668)
		(width 0.12954)
		(layer "B.Cu")
		(net "FM_CPU1_PROC_ID1")
	)
	(segment
		(start 91.74226 -274.585176)
		(end 91.731846 -274.591272)
		(width 0.0889)
		(layer "B.Cu")
		(net "FM_CPU1_PROC_ID1")
	)
	(segment
		(start 67.687444 -263.84885)
		(end 63.189104 -263.84885)
		(width 0.12954)
		(layer "B.Cu")
		(net "FM_CPU1_PROC_ID1")
	)
	(segment
		(start 42.088308 -252.68174)
		(end 42.088308 -249.19178)
		(width 0.12954)
		(layer "B.Cu")
		(net "FM_CPU1_PROC_ID1")
	)
	(segment
		(start 95.116396 -274.591272)
		(end 95.101664 -274.582636)
		(width 0.0889)
		(layer "B.Cu")
		(net "FM_CPU1_PROC_ID1")
	)
	(segment
		(start 46.890178 -257.48361)
		(end 42.088308 -252.68174)
		(width 0.12954)
		(layer "B.Cu")
		(net "FM_CPU1_PROC_ID1")
	)
	(segment
		(start 52.782978 -260.912356)
		(end 52.782978 -258.25323)
		(width 0.12954)
		(layer "B.Cu")
		(net "FM_CPU1_PROC_ID1")
	)
	(segment
		(start 68.060824 -263.84885)
		(end 67.687444 -263.84885)
		(width 0.12954)
		(layer "B.Cu")
		(net "FM_CPU1_PROC_ID1")
	)
	(segment
		(start 58.820812 -263.89711)
		(end 55.767732 -263.89711)
		(width 0.12954)
		(layer "B.Cu")
		(net "FM_CPU1_PROC_ID1")
	)
	(segment
		(start 63.189104 -263.84885)
		(end 62.767464 -264.27049)
		(width 0.12954)
		(layer "B.Cu")
		(net "FM_CPU1_PROC_ID1")
	)
	(segment
		(start 99.815396 -274.591272)
		(end 99.800664 -274.582636)
		(width 0.0889)
		(layer "B.Cu")
		(net "FM_CPU1_PROC_ID1")
	)
	(segment
		(start 103.196644 -274.257008)
		(end 103.196644 -274.266914)
		(width 0.0889)
		(layer "B.Cu")
		(net "FM_CPU1_PROC_ID1")
	)
	(arc
		(start 100.189792 -274.591272)
		(mid 100.002594 -274.641415)
		(end 99.815396 -274.591272)
		(width 0.0889)
		(layer "B.Cu")
		(net "FM_CPU1_PROC_ID1")
	)
	(arc
		(start 92.296996 -274.591272)
		(mid 92.020437 -274.515529)
		(end 91.74226 -274.585176)
		(width 0.0889)
		(layer "B.Cu")
		(net "FM_CPU1_PROC_ID1")
	)
	(arc
		(start 86.092284 -274.591272)
		(mid 85.905086 -274.641415)
		(end 85.717888 -274.591272)
		(width 0.0889)
		(layer "B.Cu")
		(net "FM_CPU1_PROC_ID1")
	)
	(arc
		(start 91.731846 -274.591272)
		(mid 91.544648 -274.641415)
		(end 91.35745 -274.591272)
		(width 0.0889)
		(layer "B.Cu")
		(net "FM_CPU1_PROC_ID1")
	)
	(arc
		(start 90.791792 -274.591272)
		(mid 90.604594 -274.641415)
		(end 90.417396 -274.591272)
		(width 0.0889)
		(layer "B.Cu")
		(net "FM_CPU1_PROC_ID1")
	)
	(arc
		(start 96.041464 -274.582636)
		(mid 95.764989 -274.515316)
		(end 95.490792 -274.591272)
		(width 0.0889)
		(layer "B.Cu")
		(net "FM_CPU1_PROC_ID1")
	)
	(arc
		(start 99.800664 -274.582636)
		(mid 99.524189 -274.515316)
		(end 99.249992 -274.591272)
		(width 0.0889)
		(layer "B.Cu")
		(net "FM_CPU1_PROC_ID1")
	)
	(arc
		(start 96.430592 -274.591272)
		(mid 96.243394 -274.641415)
		(end 96.056196 -274.591272)
		(width 0.0889)
		(layer "B.Cu")
		(net "FM_CPU1_PROC_ID1")
	)
	(arc
		(start 89.477596 -274.591272)
		(mid 89.194894 -274.515496)
		(end 88.912192 -274.591272)
		(width 0.0889)
		(layer "B.Cu")
		(net "FM_CPU1_PROC_ID1")
	)
	(arc
		(start 95.101664 -274.582636)
		(mid 94.825189 -274.515316)
		(end 94.550992 -274.591272)
		(width 0.0889)
		(layer "B.Cu")
		(net "FM_CPU1_PROC_ID1")
	)
	(arc
		(start 85.703156 -274.582636)
		(mid 85.572118 -274.531841)
		(end 85.432646 -274.514564)
		(width 0.0889)
		(layer "B.Cu")
		(net "FM_CPU1_PROC_ID1")
	)
	(arc
		(start 103.196644 -274.266914)
		(mid 103.148965 -274.449814)
		(end 103.018082 -274.586192)
		(width 0.0889)
		(layer "B.Cu")
		(net "FM_CPU1_PROC_ID1")
	)
	(arc
		(start 93.611192 -274.591272)
		(mid 93.423994 -274.641415)
		(end 93.236796 -274.591272)
		(width 0.0889)
		(layer "B.Cu")
		(net "FM_CPU1_PROC_ID1")
	)
	(arc
		(start 96.981264 -274.582636)
		(mid 96.704789 -274.515316)
		(end 96.430592 -274.591272)
		(width 0.0889)
		(layer "B.Cu")
		(net "FM_CPU1_PROC_ID1")
	)
	(arc
		(start 103.479092 -273.777456)
		(mid 103.274757 -273.980061)
		(end 103.196644 -274.257008)
		(width 0.0889)
		(layer "B.Cu")
		(net "FM_CPU1_PROC_ID1")
	)
	(arc
		(start 87.032592 -274.591272)
		(mid 86.845394 -274.641415)
		(end 86.658196 -274.591272)
		(width 0.0889)
		(layer "B.Cu")
		(net "FM_CPU1_PROC_ID1")
	)
	(arc
		(start 86.658196 -274.591272)
		(mid 86.37524 -274.515369)
		(end 86.092284 -274.591272)
		(width 0.0889)
		(layer "B.Cu")
		(net "FM_CPU1_PROC_ID1")
	)
	(arc
		(start 104.98455 -273.777456)
		(mid 104.710351 -273.701621)
		(end 104.433878 -273.76882)
		(width 0.0889)
		(layer "B.Cu")
		(net "FM_CPU1_PROC_ID1")
	)
	(arc
		(start 97.370392 -274.591272)
		(mid 97.183194 -274.641415)
		(end 96.995996 -274.591272)
		(width 0.0889)
		(layer "B.Cu")
		(net "FM_CPU1_PROC_ID1")
	)
	(arc
		(start 88.537796 -274.591272)
		(mid 88.255094 -274.515496)
		(end 87.972392 -274.591272)
		(width 0.0889)
		(layer "B.Cu")
		(net "FM_CPU1_PROC_ID1")
	)
	(arc
		(start 98.310192 -274.591272)
		(mid 98.122994 -274.641415)
		(end 97.935796 -274.591272)
		(width 0.0889)
		(layer "B.Cu")
		(net "FM_CPU1_PROC_ID1")
	)
	(arc
		(start 104.04475 -273.777456)
		(mid 103.767937 -273.701586)
		(end 103.489506 -273.77136)
		(width 0.0889)
		(layer "B.Cu")
		(net "FM_CPU1_PROC_ID1")
	)
	(arc
		(start 94.550992 -274.591272)
		(mid 94.363794 -274.641415)
		(end 94.176596 -274.591272)
		(width 0.0889)
		(layer "B.Cu")
		(net "FM_CPU1_PROC_ID1")
	)
	(arc
		(start 101.129592 -274.591272)
		(mid 100.942394 -274.641415)
		(end 100.755196 -274.591272)
		(width 0.0889)
		(layer "B.Cu")
		(net "FM_CPU1_PROC_ID1")
	)
	(arc
		(start 105.92435 -273.777456)
		(mid 105.650151 -273.701621)
		(end 105.373678 -273.76882)
		(width 0.0889)
		(layer "B.Cu")
		(net "FM_CPU1_PROC_ID1")
	)
	(arc
		(start 102.069392 -274.591272)
		(mid 101.882194 -274.641415)
		(end 101.694996 -274.591272)
		(width 0.0889)
		(layer "B.Cu")
		(net "FM_CPU1_PROC_ID1")
	)
	(arc
		(start 103.009192 -274.591272)
		(mid 102.821994 -274.641415)
		(end 102.634796 -274.591272)
		(width 0.0889)
		(layer "B.Cu")
		(net "FM_CPU1_PROC_ID1")
	)
	(arc
		(start 106.80573 -273.747992)
		(mid 106.557225 -273.702005)
		(end 106.313478 -273.76882)
		(width 0.0889)
		(layer "B.Cu")
		(net "FM_CPU1_PROC_ID1")
	)
	(arc
		(start 98.875596 -274.591272)
		(mid 98.592894 -274.515496)
		(end 98.310192 -274.591272)
		(width 0.0889)
		(layer "B.Cu")
		(net "FM_CPU1_PROC_ID1")
	)
	(arc
		(start 102.620064 -274.582636)
		(mid 102.343589 -274.515316)
		(end 102.069392 -274.591272)
		(width 0.0889)
		(layer "B.Cu")
		(net "FM_CPU1_PROC_ID1")
	)
	(arc
		(start 92.671392 -274.591272)
		(mid 92.484194 -274.641415)
		(end 92.296996 -274.591272)
		(width 0.0889)
		(layer "B.Cu")
		(net "FM_CPU1_PROC_ID1")
	)
	(arc
		(start 87.972392 -274.591272)
		(mid 87.785194 -274.641415)
		(end 87.597996 -274.591272)
		(width 0.0889)
		(layer "B.Cu")
		(net "FM_CPU1_PROC_ID1")
	)
	(arc
		(start 94.161864 -274.582636)
		(mid 93.885389 -274.515316)
		(end 93.611192 -274.591272)
		(width 0.0889)
		(layer "B.Cu")
		(net "FM_CPU1_PROC_ID1")
	)
	(arc
		(start 90.417396 -274.591272)
		(mid 90.134694 -274.515496)
		(end 89.851992 -274.591272)
		(width 0.0889)
		(layer "B.Cu")
		(net "FM_CPU1_PROC_ID1")
	)
	(arc
		(start 87.597996 -274.591272)
		(mid 87.323797 -274.515437)
		(end 87.047324 -274.582636)
		(width 0.0889)
		(layer "B.Cu")
		(net "FM_CPU1_PROC_ID1")
	)
	(arc
		(start 93.222064 -274.582636)
		(mid 92.945589 -274.515316)
		(end 92.671392 -274.591272)
		(width 0.0889)
		(layer "B.Cu")
		(net "FM_CPU1_PROC_ID1")
	)
	(arc
		(start 91.347036 -274.585176)
		(mid 91.068604 -274.51533)
		(end 90.791792 -274.591272)
		(width 0.0889)
		(layer "B.Cu")
		(net "FM_CPU1_PROC_ID1")
	)
	(arc
		(start 89.851992 -274.591272)
		(mid 89.664794 -274.641415)
		(end 89.477596 -274.591272)
		(width 0.0889)
		(layer "B.Cu")
		(net "FM_CPU1_PROC_ID1")
	)
	(arc
		(start 104.419146 -273.777456)
		(mid 104.231948 -273.827599)
		(end 104.04475 -273.777456)
		(width 0.0889)
		(layer "B.Cu")
		(net "FM_CPU1_PROC_ID1")
	)
	(arc
		(start 105.358946 -273.777456)
		(mid 105.171748 -273.827599)
		(end 104.98455 -273.777456)
		(width 0.0889)
		(layer "B.Cu")
		(net "FM_CPU1_PROC_ID1")
	)
	(arc
		(start 99.249992 -274.591272)
		(mid 99.062794 -274.641415)
		(end 98.875596 -274.591272)
		(width 0.0889)
		(layer "B.Cu")
		(net "FM_CPU1_PROC_ID1")
	)
	(arc
		(start 101.680264 -274.582636)
		(mid 101.403789 -274.515316)
		(end 101.129592 -274.591272)
		(width 0.0889)
		(layer "B.Cu")
		(net "FM_CPU1_PROC_ID1")
	)
	(arc
		(start 97.921064 -274.582636)
		(mid 97.644589 -274.515316)
		(end 97.370392 -274.591272)
		(width 0.0889)
		(layer "B.Cu")
		(net "FM_CPU1_PROC_ID1")
	)
	(arc
		(start 106.298746 -273.777456)
		(mid 106.111548 -273.827599)
		(end 105.92435 -273.777456)
		(width 0.0889)
		(layer "B.Cu")
		(net "FM_CPU1_PROC_ID1")
	)
	(arc
		(start 95.490792 -274.591272)
		(mid 95.303594 -274.641415)
		(end 95.116396 -274.591272)
		(width 0.0889)
		(layer "B.Cu")
		(net "FM_CPU1_PROC_ID1")
	)
	(arc
		(start 100.740464 -274.582636)
		(mid 100.463989 -274.515316)
		(end 100.189792 -274.591272)
		(width 0.0889)
		(layer "B.Cu")
		(net "FM_CPU1_PROC_ID1")
	)
	(arc
		(start 88.912192 -274.591272)
		(mid 88.724994 -274.641415)
		(end 88.537796 -274.591272)
		(width 0.0889)
		(layer "B.Cu")
		(net "FM_CPU1_PROC_ID1")
	)
	(segment
		(start 181.53888 -131.003548)
		(end 181.34584 -130.810508)
		(width 0.127)
		(layer "In4.Cu")
		(net "FM_CPU1_PROC_ID1")
	)
	(segment
		(start 181.53888 -131.790948)
		(end 181.53888 -131.003548)
		(width 0.127)
		(layer "In4.Cu")
		(net "FM_CPU1_PROC_ID1")
	)
	(segment
		(start 72.494648 -180.8099)
		(end 71.3486 -181.955948)
		(width 0.127)
		(layer "In4.Cu")
		(net "FM_CPU1_PROC_ID1")
	)
	(segment
		(start 172.70984 -130.810508)
		(end 172.12818 -130.228848)
		(width 0.127)
		(layer "In4.Cu")
		(net "FM_CPU1_PROC_ID1")
	)
	(segment
		(start 52.324 -185.283348)
		(end 51.72964 -185.877708)
		(width 0.127)
		(layer "In4.Cu")
		(net "FM_CPU1_PROC_ID1")
	)
	(segment
		(start 68.83146 -182.339488)
		(end 66.57594 -182.339488)
		(width 0.127)
		(layer "In4.Cu")
		(net "FM_CPU1_PROC_ID1")
	)
	(segment
		(start 168.34358 -130.228848)
		(end 165.830758 -132.74167)
		(width 0.127)
		(layer "In4.Cu")
		(net "FM_CPU1_PROC_ID1")
	)
	(segment
		(start 53.62448 -185.283348)
		(end 52.324 -185.283348)
		(width 0.127)
		(layer "In4.Cu")
		(net "FM_CPU1_PROC_ID1")
	)
	(segment
		(start 142.145512 -133.543548)
		(end 127.789686 -147.899374)
		(width 0.127)
		(layer "In4.Cu")
		(net "FM_CPU1_PROC_ID1")
	)
	(segment
		(start 53.87848 -185.537348)
		(end 53.62448 -185.283348)
		(width 0.127)
		(layer "In4.Cu")
		(net "FM_CPU1_PROC_ID1")
	)
	(segment
		(start 162.832542 -133.543548)
		(end 142.145512 -133.543548)
		(width 0.127)
		(layer "In4.Cu")
		(net "FM_CPU1_PROC_ID1")
	)
	(segment
		(start 69.215 -181.955948)
		(end 68.83146 -182.339488)
		(width 0.127)
		(layer "In4.Cu")
		(net "FM_CPU1_PROC_ID1")
	)
	(segment
		(start 181.34584 -130.810508)
		(end 172.70984 -130.810508)
		(width 0.127)
		(layer "In4.Cu")
		(net "FM_CPU1_PROC_ID1")
	)
	(segment
		(start 71.3486 -181.955948)
		(end 69.215 -181.955948)
		(width 0.127)
		(layer "In4.Cu")
		(net "FM_CPU1_PROC_ID1")
	)
	(segment
		(start 165.830758 -132.74167)
		(end 163.63442 -132.74167)
		(width 0.127)
		(layer "In4.Cu")
		(net "FM_CPU1_PROC_ID1")
	)
	(segment
		(start 127.789686 -147.899374)
		(end 109.900974 -147.899374)
		(width 0.127)
		(layer "In4.Cu")
		(net "FM_CPU1_PROC_ID1")
	)
	(segment
		(start 163.63442 -132.74167)
		(end 162.832542 -133.543548)
		(width 0.127)
		(layer "In4.Cu")
		(net "FM_CPU1_PROC_ID1")
	)
	(segment
		(start 76.990448 -180.8099)
		(end 72.494648 -180.8099)
		(width 0.127)
		(layer "In4.Cu")
		(net "FM_CPU1_PROC_ID1")
	)
	(segment
		(start 66.57594 -182.339488)
		(end 63.37808 -185.537348)
		(width 0.127)
		(layer "In4.Cu")
		(net "FM_CPU1_PROC_ID1")
	)
	(segment
		(start 182.17388 -132.425948)
		(end 181.53888 -131.790948)
		(width 0.127)
		(layer "In4.Cu")
		(net "FM_CPU1_PROC_ID1")
	)
	(segment
		(start 172.12818 -130.228848)
		(end 168.34358 -130.228848)
		(width 0.127)
		(layer "In4.Cu")
		(net "FM_CPU1_PROC_ID1")
	)
	(segment
		(start 63.37808 -185.537348)
		(end 53.87848 -185.537348)
		(width 0.127)
		(layer "In4.Cu")
		(net "FM_CPU1_PROC_ID1")
	)
	(segment
		(start 109.900974 -147.899374)
		(end 76.990448 -180.8099)
		(width 0.127)
		(layer "In4.Cu")
		(net "FM_CPU1_PROC_ID1")
	)
	(segment
		(start 179.96408 -124.475748)
		(end 179.96408 -121.984008)
		(width 0.12954)
		(layer "F.Cu")
		(net "FM_CPU1_PROC_ID0")
	)
	(segment
		(start 106.581448 -273.730974)
		(end 106.581448 -274.26666)
		(width 0.12954)
		(layer "F.Cu")
		(net "FM_CPU1_PROC_ID0")
	)
	(segment
		(start 179.12588 -125.313948)
		(end 179.96408 -124.475748)
		(width 0.12954)
		(layer "F.Cu")
		(net "FM_CPU1_PROC_ID0")
	)
	(segment
		(start 106.581448 -274.26666)
		(end 106.581194 -274.266914)
		(width 0.12954)
		(layer "F.Cu")
		(net "FM_CPU1_PROC_ID0")
	)
	(segment
		(start 179.96408 -121.984008)
		(end 179.755546 -121.775474)
		(width 0.12954)
		(layer "F.Cu")
		(net "FM_CPU1_PROC_ID0")
	)
	(segment
		(start 179.12588 -132.425948)
		(end 179.88788 -131.663948)
		(width 0.12954)
		(layer "F.Cu")
		(net "FM_CPU1_PROC_ID0")
	)
	(segment
		(start 179.53355 -126.564898)
		(end 179.12588 -126.564898)
		(width 0.12954)
		(layer "F.Cu")
		(net "FM_CPU1_PROC_ID0")
	)
	(segment
		(start 179.88788 -131.663948)
		(end 179.88788 -126.919228)
		(width 0.12954)
		(layer "F.Cu")
		(net "FM_CPU1_PROC_ID0")
	)
	(segment
		(start 179.12588 -126.564898)
		(end 179.12588 -125.313948)
		(width 0.12954)
		(layer "F.Cu")
		(net "FM_CPU1_PROC_ID0")
	)
	(segment
		(start 179.88788 -126.919228)
		(end 179.53355 -126.564898)
		(width 0.12954)
		(layer "F.Cu")
		(net "FM_CPU1_PROC_ID0")
	)
	(via
		(at 51.10988 -187.112148)
		(size 0.508)
		(drill 0.254)
		(layers "F.Cu" "B.Cu")
		(net "FM_CPU1_PROC_ID0")
	)
	(via
		(at 179.12588 -132.425948)
		(size 0.508)
		(drill 0.254)
		(layers "F.Cu" "B.Cu")
		(net "FM_CPU1_PROC_ID0")
	)
	(via
		(at 106.581194 -274.266914)
		(size 0.4572)
		(drill 0.2032)
		(layers "F.Cu" "B.Cu")
		(net "FM_CPU1_PROC_ID0")
	)
	(via
		(at 179.12588 -125.313948)
		(size 0.762)
		(drill 0.381)
		(layers "F.Cu" "B.Cu")
		(net "FM_CPU1_PROC_ID0")
	)
	(segment
		(start 40.105838 -252.06579)
		(end 40.105838 -194.17919)
		(width 0.12954)
		(layer "B.Cu")
		(net "FM_CPU1_PROC_ID0")
	)
	(segment
		(start 101.614478 -274.765008)
		(end 101.599746 -274.756372)
		(width 0.0889)
		(layer "B.Cu")
		(net "FM_CPU1_PROC_ID0")
	)
	(segment
		(start 59.912504 -266.02817)
		(end 59.490864 -265.60653)
		(width 0.12954)
		(layer "B.Cu")
		(net "FM_CPU1_PROC_ID0")
	)
	(segment
		(start 81.975198 -275.257768)
		(end 81.974944 -275.258022)
		(width 0.12954)
		(layer "B.Cu")
		(net "FM_CPU1_PROC_ID0")
	)
	(segment
		(start 51.551078 -257.89763)
		(end 46.524418 -257.89763)
		(width 0.12954)
		(layer "B.Cu")
		(net "FM_CPU1_PROC_ID0")
	)
	(segment
		(start 41.670478 -253.04369)
		(end 41.083738 -253.04369)
		(width 0.12954)
		(layer "B.Cu")
		(net "FM_CPU1_PROC_ID0")
	)
	(segment
		(start 98.790506 -274.762468)
		(end 98.780092 -274.756372)
		(width 0.0889)
		(layer "B.Cu")
		(net "FM_CPU1_PROC_ID0")
	)
	(segment
		(start 52.795424 -263.14273)
		(end 51.680618 -262.027924)
		(width 0.12954)
		(layer "B.Cu")
		(net "FM_CPU1_PROC_ID0")
	)
	(segment
		(start 102.554278 -274.765008)
		(end 102.539546 -274.756372)
		(width 0.0889)
		(layer "B.Cu")
		(net "FM_CPU1_PROC_ID0")
	)
	(segment
		(start 104.514396 -273.942556)
		(end 104.499664 -273.951192)
		(width 0.0889)
		(layer "B.Cu")
		(net "FM_CPU1_PROC_ID0")
	)
	(segment
		(start 95.035878 -274.765008)
		(end 95.021146 -274.756372)
		(width 0.0889)
		(layer "B.Cu")
		(net "FM_CPU1_PROC_ID0")
	)
	(segment
		(start 92.211906 -274.762468)
		(end 92.201492 -274.756372)
		(width 0.0889)
		(layer "B.Cu")
		(net "FM_CPU1_PROC_ID0")
	)
	(segment
		(start 90.332306 -274.762468)
		(end 90.321892 -274.756372)
		(width 0.0889)
		(layer "B.Cu")
		(net "FM_CPU1_PROC_ID0")
	)
	(segment
		(start 59.490864 -265.60653)
		(end 55.719472 -265.60653)
		(width 0.12954)
		(layer "B.Cu")
		(net "FM_CPU1_PROC_ID0")
	)
	(segment
		(start 53.255672 -263.14273)
		(end 52.795424 -263.14273)
		(width 0.12954)
		(layer "B.Cu")
		(net "FM_CPU1_PROC_ID0")
	)
	(segment
		(start 68.677282 -265.16965)
		(end 63.588392 -265.16965)
		(width 0.12954)
		(layer "B.Cu")
		(net "FM_CPU1_PROC_ID0")
	)
	(segment
		(start 103.387144 -274.266914)
		(end 103.387144 -274.282408)
		(width 0.0889)
		(layer "B.Cu")
		(net "FM_CPU1_PROC_ID0")
	)
	(segment
		(start 99.734878 -274.765008)
		(end 99.720146 -274.756372)
		(width 0.0889)
		(layer "B.Cu")
		(net "FM_CPU1_PROC_ID0")
	)
	(segment
		(start 106.393996 -273.942556)
		(end 106.379264 -273.951192)
		(width 0.0889)
		(layer "B.Cu")
		(net "FM_CPU1_PROC_ID0")
	)
	(segment
		(start 105.454196 -273.942556)
		(end 105.439464 -273.951192)
		(width 0.0889)
		(layer "B.Cu")
		(net "FM_CPU1_PROC_ID0")
	)
	(segment
		(start 40.105838 -194.17919)
		(end 44.07408 -190.210948)
		(width 0.12954)
		(layer "B.Cu")
		(net "FM_CPU1_PROC_ID0")
	)
	(segment
		(start 55.719472 -265.60653)
		(end 53.255672 -263.14273)
		(width 0.12954)
		(layer "B.Cu")
		(net "FM_CPU1_PROC_ID0")
	)
	(segment
		(start 97.85096 -274.762468)
		(end 97.840546 -274.756372)
		(width 0.0889)
		(layer "B.Cu")
		(net "FM_CPU1_PROC_ID0")
	)
	(segment
		(start 106.737658 -273.995896)
		(end 106.716576 -273.917918)
		(width 0.0889)
		(layer "B.Cu")
		(net "FM_CPU1_PROC_ID0")
	)
	(segment
		(start 106.581194 -274.266914)
		(end 106.737658 -273.995896)
		(width 0.0889)
		(layer "B.Cu")
		(net "FM_CPU1_PROC_ID0")
	)
	(segment
		(start 96.915478 -274.765008)
		(end 96.900746 -274.756372)
		(width 0.0889)
		(layer "B.Cu")
		(net "FM_CPU1_PROC_ID0")
	)
	(segment
		(start 85.247988 -274.756372)
		(end 84.380578 -275.257768)
		(width 0.0889)
		(layer "B.Cu")
		(net "FM_CPU1_PROC_ID0")
	)
	(segment
		(start 46.524418 -257.89763)
		(end 41.670478 -253.04369)
		(width 0.12954)
		(layer "B.Cu")
		(net "FM_CPU1_PROC_ID0")
	)
	(segment
		(start 100.674678 -274.765008)
		(end 100.659946 -274.756372)
		(width 0.0889)
		(layer "B.Cu")
		(net "FM_CPU1_PROC_ID0")
	)
	(segment
		(start 87.502492 -274.756372)
		(end 87.502238 -274.756372)
		(width 0.0889)
		(layer "B.Cu")
		(net "FM_CPU1_PROC_ID0")
	)
	(segment
		(start 62.729872 -266.02817)
		(end 59.912504 -266.02817)
		(width 0.12954)
		(layer "B.Cu")
		(net "FM_CPU1_PROC_ID0")
	)
	(segment
		(start 49.86528 -190.210948)
		(end 51.10988 -188.966348)
		(width 0.12954)
		(layer "B.Cu")
		(net "FM_CPU1_PROC_ID0")
	)
	(segment
		(start 93.156278 -274.765008)
		(end 93.141546 -274.756372)
		(width 0.0889)
		(layer "B.Cu")
		(net "FM_CPU1_PROC_ID0")
	)
	(segment
		(start 63.588392 -265.16965)
		(end 62.729872 -266.02817)
		(width 0.12954)
		(layer "B.Cu")
		(net "FM_CPU1_PROC_ID0")
	)
	(segment
		(start 44.07408 -190.210948)
		(end 49.86528 -190.210948)
		(width 0.12954)
		(layer "B.Cu")
		(net "FM_CPU1_PROC_ID0")
	)
	(segment
		(start 85.63737 -274.765008)
		(end 85.622638 -274.756372)
		(width 0.0889)
		(layer "B.Cu")
		(net "FM_CPU1_PROC_ID0")
	)
	(segment
		(start 103.574596 -273.942556)
		(end 103.565706 -273.947636)
		(width 0.0889)
		(layer "B.Cu")
		(net "FM_CPU1_PROC_ID0")
	)
	(segment
		(start 85.622638 -274.756372)
		(end 85.614256 -274.751546)
		(width 0.0889)
		(layer "B.Cu")
		(net "FM_CPU1_PROC_ID0")
	)
	(segment
		(start 94.096078 -274.765008)
		(end 94.081346 -274.756372)
		(width 0.0889)
		(layer "B.Cu")
		(net "FM_CPU1_PROC_ID0")
	)
	(segment
		(start 84.380578 -275.257768)
		(end 81.975198 -275.257768)
		(width 0.12954)
		(layer "B.Cu")
		(net "FM_CPU1_PROC_ID0")
	)
	(segment
		(start 81.974944 -275.258022)
		(end 78.765654 -275.258022)
		(width 0.12954)
		(layer "B.Cu")
		(net "FM_CPU1_PROC_ID0")
	)
	(segment
		(start 91.827096 -274.756372)
		(end 91.816682 -274.762468)
		(width 0.0889)
		(layer "B.Cu")
		(net "FM_CPU1_PROC_ID0")
	)
	(segment
		(start 51.680618 -262.027924)
		(end 51.680618 -258.02717)
		(width 0.12954)
		(layer "B.Cu")
		(net "FM_CPU1_PROC_ID0")
	)
	(segment
		(start 51.680618 -258.02717)
		(end 51.551078 -257.89763)
		(width 0.12954)
		(layer "B.Cu")
		(net "FM_CPU1_PROC_ID0")
	)
	(segment
		(start 41.083738 -253.04369)
		(end 40.105838 -252.06579)
		(width 0.12954)
		(layer "B.Cu")
		(net "FM_CPU1_PROC_ID0")
	)
	(segment
		(start 78.765654 -275.258022)
		(end 68.677282 -265.16965)
		(width 0.12954)
		(layer "B.Cu")
		(net "FM_CPU1_PROC_ID0")
	)
	(segment
		(start 51.10988 -188.966348)
		(end 51.10988 -187.112148)
		(width 0.12954)
		(layer "B.Cu")
		(net "FM_CPU1_PROC_ID0")
	)
	(segment
		(start 95.975678 -274.765008)
		(end 95.960946 -274.756372)
		(width 0.0889)
		(layer "B.Cu")
		(net "FM_CPU1_PROC_ID0")
	)
	(segment
		(start 87.127842 -274.756372)
		(end 87.11311 -274.765008)
		(width 0.0889)
		(layer "B.Cu")
		(net "FM_CPU1_PROC_ID0")
	)
	(arc
		(start 105.828592 -273.942556)
		(mid 105.641394 -273.892413)
		(end 105.454196 -273.942556)
		(width 0.0889)
		(layer "B.Cu")
		(net "FM_CPU1_PROC_ID0")
	)
	(arc
		(start 85.614256 -274.751546)
		(mid 85.430494 -274.706146)
		(end 85.247988 -274.756372)
		(width 0.0889)
		(layer "B.Cu")
		(net "FM_CPU1_PROC_ID0")
	)
	(arc
		(start 103.948992 -273.942556)
		(mid 103.761794 -273.892413)
		(end 103.574596 -273.942556)
		(width 0.0889)
		(layer "B.Cu")
		(net "FM_CPU1_PROC_ID0")
	)
	(arc
		(start 106.379264 -273.951192)
		(mid 106.102789 -274.018512)
		(end 105.828592 -273.942556)
		(width 0.0889)
		(layer "B.Cu")
		(net "FM_CPU1_PROC_ID0")
	)
	(arc
		(start 92.76715 -274.756372)
		(mid 92.490337 -274.832242)
		(end 92.211906 -274.762468)
		(width 0.0889)
		(layer "B.Cu")
		(net "FM_CPU1_PROC_ID0")
	)
	(arc
		(start 103.10495 -274.756372)
		(mid 102.830751 -274.832207)
		(end 102.554278 -274.765008)
		(width 0.0889)
		(layer "B.Cu")
		(net "FM_CPU1_PROC_ID0")
	)
	(arc
		(start 95.58655 -274.756372)
		(mid 95.312351 -274.832207)
		(end 95.035878 -274.765008)
		(width 0.0889)
		(layer "B.Cu")
		(net "FM_CPU1_PROC_ID0")
	)
	(arc
		(start 103.387144 -274.282408)
		(mid 103.307774 -274.556142)
		(end 103.10495 -274.756372)
		(width 0.0889)
		(layer "B.Cu")
		(net "FM_CPU1_PROC_ID0")
	)
	(arc
		(start 92.201492 -274.756372)
		(mid 92.014294 -274.706229)
		(end 91.827096 -274.756372)
		(width 0.0889)
		(layer "B.Cu")
		(net "FM_CPU1_PROC_ID0")
	)
	(arc
		(start 106.716576 -273.917918)
		(mid 106.55248 -273.893571)
		(end 106.393996 -273.942556)
		(width 0.0889)
		(layer "B.Cu")
		(net "FM_CPU1_PROC_ID0")
	)
	(arc
		(start 96.52635 -274.756372)
		(mid 96.252151 -274.832207)
		(end 95.975678 -274.765008)
		(width 0.0889)
		(layer "B.Cu")
		(net "FM_CPU1_PROC_ID0")
	)
	(arc
		(start 105.439464 -273.951192)
		(mid 105.162989 -274.018512)
		(end 104.888792 -273.942556)
		(width 0.0889)
		(layer "B.Cu")
		(net "FM_CPU1_PROC_ID0")
	)
	(arc
		(start 89.007696 -274.756372)
		(mid 88.724994 -274.832148)
		(end 88.442292 -274.756372)
		(width 0.0889)
		(layer "B.Cu")
		(net "FM_CPU1_PROC_ID0")
	)
	(arc
		(start 91.816682 -274.762468)
		(mid 91.538504 -274.832191)
		(end 91.261946 -274.756372)
		(width 0.0889)
		(layer "B.Cu")
		(net "FM_CPU1_PROC_ID0")
	)
	(arc
		(start 88.067896 -274.756372)
		(mid 87.785194 -274.832148)
		(end 87.502492 -274.756372)
		(width 0.0889)
		(layer "B.Cu")
		(net "FM_CPU1_PROC_ID0")
	)
	(arc
		(start 101.22535 -274.756372)
		(mid 100.951151 -274.832207)
		(end 100.674678 -274.765008)
		(width 0.0889)
		(layer "B.Cu")
		(net "FM_CPU1_PROC_ID0")
	)
	(arc
		(start 93.141546 -274.756372)
		(mid 92.954348 -274.706229)
		(end 92.76715 -274.756372)
		(width 0.0889)
		(layer "B.Cu")
		(net "FM_CPU1_PROC_ID0")
	)
	(arc
		(start 99.34575 -274.756372)
		(mid 99.068937 -274.832242)
		(end 98.790506 -274.762468)
		(width 0.0889)
		(layer "B.Cu")
		(net "FM_CPU1_PROC_ID0")
	)
	(arc
		(start 100.28555 -274.756372)
		(mid 100.011351 -274.832207)
		(end 99.734878 -274.765008)
		(width 0.0889)
		(layer "B.Cu")
		(net "FM_CPU1_PROC_ID0")
	)
	(arc
		(start 86.562438 -274.756372)
		(mid 86.37524 -274.706229)
		(end 86.188042 -274.756372)
		(width 0.0889)
		(layer "B.Cu")
		(net "FM_CPU1_PROC_ID0")
	)
	(arc
		(start 102.539546 -274.756372)
		(mid 102.352348 -274.706229)
		(end 102.16515 -274.756372)
		(width 0.0889)
		(layer "B.Cu")
		(net "FM_CPU1_PROC_ID0")
	)
	(arc
		(start 91.261946 -274.756372)
		(mid 91.074748 -274.706229)
		(end 90.88755 -274.756372)
		(width 0.0889)
		(layer "B.Cu")
		(net "FM_CPU1_PROC_ID0")
	)
	(arc
		(start 87.502238 -274.756372)
		(mid 87.31504 -274.706229)
		(end 87.127842 -274.756372)
		(width 0.0889)
		(layer "B.Cu")
		(net "FM_CPU1_PROC_ID0")
	)
	(arc
		(start 102.16515 -274.756372)
		(mid 101.890951 -274.832207)
		(end 101.614478 -274.765008)
		(width 0.0889)
		(layer "B.Cu")
		(net "FM_CPU1_PROC_ID0")
	)
	(arc
		(start 87.11311 -274.765008)
		(mid 86.836635 -274.832328)
		(end 86.562438 -274.756372)
		(width 0.0889)
		(layer "B.Cu")
		(net "FM_CPU1_PROC_ID0")
	)
	(arc
		(start 89.382092 -274.756372)
		(mid 89.194894 -274.706229)
		(end 89.007696 -274.756372)
		(width 0.0889)
		(layer "B.Cu")
		(net "FM_CPU1_PROC_ID0")
	)
	(arc
		(start 93.70695 -274.756372)
		(mid 93.432751 -274.832207)
		(end 93.156278 -274.765008)
		(width 0.0889)
		(layer "B.Cu")
		(net "FM_CPU1_PROC_ID0")
	)
	(arc
		(start 98.780092 -274.756372)
		(mid 98.592894 -274.706229)
		(end 98.405696 -274.756372)
		(width 0.0889)
		(layer "B.Cu")
		(net "FM_CPU1_PROC_ID0")
	)
	(arc
		(start 95.960946 -274.756372)
		(mid 95.773748 -274.706229)
		(end 95.58655 -274.756372)
		(width 0.0889)
		(layer "B.Cu")
		(net "FM_CPU1_PROC_ID0")
	)
	(arc
		(start 97.46615 -274.756372)
		(mid 97.191951 -274.832207)
		(end 96.915478 -274.765008)
		(width 0.0889)
		(layer "B.Cu")
		(net "FM_CPU1_PROC_ID0")
	)
	(arc
		(start 104.888792 -273.942556)
		(mid 104.701594 -273.892413)
		(end 104.514396 -273.942556)
		(width 0.0889)
		(layer "B.Cu")
		(net "FM_CPU1_PROC_ID0")
	)
	(arc
		(start 86.188042 -274.756372)
		(mid 85.913843 -274.832207)
		(end 85.63737 -274.765008)
		(width 0.0889)
		(layer "B.Cu")
		(net "FM_CPU1_PROC_ID0")
	)
	(arc
		(start 88.442292 -274.756372)
		(mid 88.255094 -274.706229)
		(end 88.067896 -274.756372)
		(width 0.0889)
		(layer "B.Cu")
		(net "FM_CPU1_PROC_ID0")
	)
	(arc
		(start 98.405696 -274.756372)
		(mid 98.129137 -274.832115)
		(end 97.85096 -274.762468)
		(width 0.0889)
		(layer "B.Cu")
		(net "FM_CPU1_PROC_ID0")
	)
	(arc
		(start 100.659946 -274.756372)
		(mid 100.472748 -274.706229)
		(end 100.28555 -274.756372)
		(width 0.0889)
		(layer "B.Cu")
		(net "FM_CPU1_PROC_ID0")
	)
	(arc
		(start 99.720146 -274.756372)
		(mid 99.532948 -274.706229)
		(end 99.34575 -274.756372)
		(width 0.0889)
		(layer "B.Cu")
		(net "FM_CPU1_PROC_ID0")
	)
	(arc
		(start 104.499664 -273.951192)
		(mid 104.223189 -274.018512)
		(end 103.948992 -273.942556)
		(width 0.0889)
		(layer "B.Cu")
		(net "FM_CPU1_PROC_ID0")
	)
	(arc
		(start 94.64675 -274.756372)
		(mid 94.372551 -274.832207)
		(end 94.096078 -274.765008)
		(width 0.0889)
		(layer "B.Cu")
		(net "FM_CPU1_PROC_ID0")
	)
	(arc
		(start 94.081346 -274.756372)
		(mid 93.894148 -274.706229)
		(end 93.70695 -274.756372)
		(width 0.0889)
		(layer "B.Cu")
		(net "FM_CPU1_PROC_ID0")
	)
	(arc
		(start 90.88755 -274.756372)
		(mid 90.610737 -274.832242)
		(end 90.332306 -274.762468)
		(width 0.0889)
		(layer "B.Cu")
		(net "FM_CPU1_PROC_ID0")
	)
	(arc
		(start 90.321892 -274.756372)
		(mid 90.134694 -274.706229)
		(end 89.947496 -274.756372)
		(width 0.0889)
		(layer "B.Cu")
		(net "FM_CPU1_PROC_ID0")
	)
	(arc
		(start 89.947496 -274.756372)
		(mid 89.664794 -274.832148)
		(end 89.382092 -274.756372)
		(width 0.0889)
		(layer "B.Cu")
		(net "FM_CPU1_PROC_ID0")
	)
	(arc
		(start 97.840546 -274.756372)
		(mid 97.653348 -274.706229)
		(end 97.46615 -274.756372)
		(width 0.0889)
		(layer "B.Cu")
		(net "FM_CPU1_PROC_ID0")
	)
	(arc
		(start 96.900746 -274.756372)
		(mid 96.713548 -274.706229)
		(end 96.52635 -274.756372)
		(width 0.0889)
		(layer "B.Cu")
		(net "FM_CPU1_PROC_ID0")
	)
	(arc
		(start 101.599746 -274.756372)
		(mid 101.412548 -274.706229)
		(end 101.22535 -274.756372)
		(width 0.0889)
		(layer "B.Cu")
		(net "FM_CPU1_PROC_ID0")
	)
	(arc
		(start 103.565706 -273.947636)
		(mid 103.434792 -274.083996)
		(end 103.387144 -274.266914)
		(width 0.0889)
		(layer "B.Cu")
		(net "FM_CPU1_PROC_ID0")
	)
	(arc
		(start 95.021146 -274.756372)
		(mid 94.833948 -274.706229)
		(end 94.64675 -274.756372)
		(width 0.0889)
		(layer "B.Cu")
		(net "FM_CPU1_PROC_ID0")
	)
	(segment
		(start 178.17338 -133.378448)
		(end 169.91838 -133.378448)
		(width 0.127)
		(layer "In4.Cu")
		(net "FM_CPU1_PROC_ID0")
	)
	(segment
		(start 110.259114 -148.762974)
		(end 76.76134 -182.260748)
		(width 0.127)
		(layer "In4.Cu")
		(net "FM_CPU1_PROC_ID0")
	)
	(segment
		(start 166.188898 -133.60527)
		(end 164.078158 -133.60527)
		(width 0.127)
		(layer "In4.Cu")
		(net "FM_CPU1_PROC_ID0")
	)
	(segment
		(start 74.549 -182.844948)
		(end 69.7992 -182.844948)
		(width 0.127)
		(layer "In4.Cu")
		(net "FM_CPU1_PROC_ID0")
	)
	(segment
		(start 169.91838 -133.378448)
		(end 168.446196 -131.906264)
		(width 0.127)
		(layer "In4.Cu")
		(net "FM_CPU1_PROC_ID0")
	)
	(segment
		(start 164.078158 -133.60527)
		(end 163.27628 -134.407148)
		(width 0.127)
		(layer "In4.Cu")
		(net "FM_CPU1_PROC_ID0")
	)
	(segment
		(start 128.147826 -148.762974)
		(end 110.259114 -148.762974)
		(width 0.127)
		(layer "In4.Cu")
		(net "FM_CPU1_PROC_ID0")
	)
	(segment
		(start 76.76134 -182.260748)
		(end 75.1332 -182.260748)
		(width 0.127)
		(layer "In4.Cu")
		(net "FM_CPU1_PROC_ID0")
	)
	(segment
		(start 75.1332 -182.260748)
		(end 74.549 -182.844948)
		(width 0.127)
		(layer "In4.Cu")
		(net "FM_CPU1_PROC_ID0")
	)
	(segment
		(start 56.57088 -186.477148)
		(end 51.74488 -186.477148)
		(width 0.127)
		(layer "In4.Cu")
		(net "FM_CPU1_PROC_ID0")
	)
	(segment
		(start 167.887904 -131.906264)
		(end 166.188898 -133.60527)
		(width 0.127)
		(layer "In4.Cu")
		(net "FM_CPU1_PROC_ID0")
	)
	(segment
		(start 179.12588 -132.425948)
		(end 178.17338 -133.378448)
		(width 0.127)
		(layer "In4.Cu")
		(net "FM_CPU1_PROC_ID0")
	)
	(segment
		(start 64.2112 -186.400948)
		(end 56.64708 -186.400948)
		(width 0.127)
		(layer "In4.Cu")
		(net "FM_CPU1_PROC_ID0")
	)
	(segment
		(start 56.64708 -186.400948)
		(end 56.57088 -186.477148)
		(width 0.127)
		(layer "In4.Cu")
		(net "FM_CPU1_PROC_ID0")
	)
	(segment
		(start 69.7992 -182.844948)
		(end 69.3928 -183.251348)
		(width 0.127)
		(layer "In4.Cu")
		(net "FM_CPU1_PROC_ID0")
	)
	(segment
		(start 67.3608 -183.251348)
		(end 64.2112 -186.400948)
		(width 0.127)
		(layer "In4.Cu")
		(net "FM_CPU1_PROC_ID0")
	)
	(segment
		(start 51.74488 -186.477148)
		(end 51.10988 -187.112148)
		(width 0.127)
		(layer "In4.Cu")
		(net "FM_CPU1_PROC_ID0")
	)
	(segment
		(start 142.503652 -134.407148)
		(end 128.147826 -148.762974)
		(width 0.127)
		(layer "In4.Cu")
		(net "FM_CPU1_PROC_ID0")
	)
	(segment
		(start 163.27628 -134.407148)
		(end 142.503652 -134.407148)
		(width 0.127)
		(layer "In4.Cu")
		(net "FM_CPU1_PROC_ID0")
	)
	(segment
		(start 69.3928 -183.251348)
		(end 67.3608 -183.251348)
		(width 0.127)
		(layer "In4.Cu")
		(net "FM_CPU1_PROC_ID0")
	)
	(segment
		(start 168.446196 -131.906264)
		(end 167.887904 -131.906264)
		(width 0.127)
		(layer "In4.Cu")
		(net "FM_CPU1_PROC_ID0")
	)
	(segment
		(start 180.555646 -120.175528)
		(end 180.955696 -120.575578)
		(width 0.12954)
		(layer "F.Cu")
		(net "FM_CPU1_PKGID2")
	)
	(segment
		(start 185.22188 -129.866898)
		(end 185.22188 -129.256028)
		(width 0.12954)
		(layer "F.Cu")
		(net "FM_CPU1_PKGID2")
	)
	(segment
		(start 109.400594 -267.219938)
		(end 109.400594 -267.755878)
		(width 0.12954)
		(layer "F.Cu")
		(net "FM_CPU1_PKGID2")
	)
	(via
		(at 180.955696 -120.575578)
		(size 0.4572)
		(drill 0.254)
		(layers "F.Cu" "B.Cu")
		(net "FM_CPU1_PKGID2")
	)
	(via
		(at 109.400594 -267.755878)
		(size 0.4572)
		(drill 0.2032)
		(layers "F.Cu" "B.Cu")
		(net "FM_CPU1_PKGID2")
	)
	(via
		(at 185.22188 -129.256028)
		(size 0.508)
		(drill 0.254)
		(layers "F.Cu" "B.Cu")
		(net "FM_CPU1_PKGID2")
	)
	(via
		(at 60.872878 -263.03097)
		(size 0.6604)
		(drill 0.3302)
		(layers "F.Cu" "B.Cu")
		(net "FM_CPU1_PKGID2")
	)
	(via
		(at 52.12588 -187.086748)
		(size 0.508)
		(drill 0.254)
		(layers "F.Cu" "B.Cu")
		(net "FM_CPU1_PKGID2")
	)
	(segment
		(start 102.917498 -273.444462)
		(end 102.917498 -273.453098)
		(width 0.0889)
		(layer "B.Cu")
		(net "FM_CPU1_PKGID2")
	)
	(segment
		(start 107.333796 -270.687038)
		(end 107.324906 -270.692118)
		(width 0.0889)
		(layer "B.Cu")
		(net "FM_CPU1_PKGID2")
	)
	(segment
		(start 53.402738 -258.30149)
		(end 52.120038 -257.01879)
		(width 0.12954)
		(layer "B.Cu")
		(net "FM_CPU1_PKGID2")
	)
	(segment
		(start 50.22088 -191.074548)
		(end 52.12588 -189.169548)
		(width 0.12954)
		(layer "B.Cu")
		(net "FM_CPU1_PKGID2")
	)
	(segment
		(start 106.86415 -271.500854)
		(end 106.85526 -271.505934)
		(width 0.0889)
		(layer "B.Cu")
		(net "FM_CPU1_PKGID2")
	)
	(segment
		(start 55.26024 -262.462772)
		(end 55.26024 -261.917688)
		(width 0.12954)
		(layer "B.Cu")
		(net "FM_CPU1_PKGID2")
	)
	(segment
		(start 100.755196 -273.942556)
		(end 100.740464 -273.951192)
		(width 0.0889)
		(layer "B.Cu")
		(net "FM_CPU1_PKGID2")
	)
	(segment
		(start 68.05168 -263.251442)
		(end 63.63081 -263.251442)
		(width 0.12954)
		(layer "B.Cu")
		(net "FM_CPU1_PKGID2")
	)
	(segment
		(start 106.676698 -271.825212)
		(end 106.676698 -271.839436)
		(width 0.0889)
		(layer "B.Cu")
		(net "FM_CPU1_PKGID2")
	)
	(segment
		(start 85.885782 -274.174458)
		(end 85.882226 -274.170902)
		(width 0.0889)
		(layer "B.Cu")
		(net "FM_CPU1_PKGID2")
	)
	(segment
		(start 92.296996 -273.942556)
		(end 92.286582 -273.948652)
		(width 0.0889)
		(layer "B.Cu")
		(net "FM_CPU1_PKGID2")
	)
	(segment
		(start 94.176596 -273.942556)
		(end 94.161864 -273.951192)
		(width 0.0889)
		(layer "B.Cu")
		(net "FM_CPU1_PKGID2")
	)
	(segment
		(start 108.086144 -269.38351)
		(end 108.086144 -269.405608)
		(width 0.0889)
		(layer "B.Cu")
		(net "FM_CPU1_PKGID2")
	)
	(segment
		(start 107.146344 -271.011396)
		(end 107.146344 -271.02689)
		(width 0.0889)
		(layer "B.Cu")
		(net "FM_CPU1_PKGID2")
	)
	(segment
		(start 60.872878 -263.03097)
		(end 59.046364 -263.03097)
		(width 0.12954)
		(layer "B.Cu")
		(net "FM_CPU1_PKGID2")
	)
	(segment
		(start 106.393996 -272.314924)
		(end 106.385106 -272.320004)
		(width 0.0889)
		(layer "B.Cu")
		(net "FM_CPU1_PKGID2")
	)
	(segment
		(start 47.007018 -257.01879)
		(end 42.595038 -252.60681)
		(width 0.12954)
		(layer "B.Cu")
		(net "FM_CPU1_PKGID2")
	)
	(segment
		(start 56.202072 -263.404604)
		(end 55.26024 -262.462772)
		(width 0.12954)
		(layer "B.Cu")
		(net "FM_CPU1_PKGID2")
	)
	(segment
		(start 97.935796 -273.942556)
		(end 97.921064 -273.951192)
		(width 0.0889)
		(layer "B.Cu")
		(net "FM_CPU1_PKGID2")
	)
	(segment
		(start 104.433878 -273.137376)
		(end 104.419146 -273.12874)
		(width 0.0889)
		(layer "B.Cu")
		(net "FM_CPU1_PKGID2")
	)
	(segment
		(start 102.634796 -273.942556)
		(end 102.620064 -273.951192)
		(width 0.0889)
		(layer "B.Cu")
		(net "FM_CPU1_PKGID2")
	)
	(segment
		(start 93.236796 -273.942556)
		(end 93.222064 -273.951192)
		(width 0.0889)
		(layer "B.Cu")
		(net "FM_CPU1_PKGID2")
	)
	(segment
		(start 84.128356 -274.170902)
		(end 78.97114 -274.170902)
		(width 0.12954)
		(layer "B.Cu")
		(net "FM_CPU1_PKGID2")
	)
	(segment
		(start 103.489506 -273.134836)
		(end 103.479092 -273.12874)
		(width 0.0889)
		(layer "B.Cu")
		(net "FM_CPU1_PKGID2")
	)
	(segment
		(start 52.120038 -257.01879)
		(end 47.007018 -257.01879)
		(width 0.12954)
		(layer "B.Cu")
		(net "FM_CPU1_PKGID2")
	)
	(segment
		(start 44.48048 -191.074548)
		(end 50.22088 -191.074548)
		(width 0.12954)
		(layer "B.Cu")
		(net "FM_CPU1_PKGID2")
	)
	(segment
		(start 109.113066 -268.043406)
		(end 108.775246 -268.043406)
		(width 0.0889)
		(layer "B.Cu")
		(net "FM_CPU1_PKGID2")
	)
	(segment
		(start 106.206544 -272.639282)
		(end 106.206544 -272.654776)
		(width 0.0889)
		(layer "B.Cu")
		(net "FM_CPU1_PKGID2")
	)
	(segment
		(start 108.279692 -269.055596)
		(end 108.273596 -269.059152)
		(width 0.0889)
		(layer "B.Cu")
		(net "FM_CPU1_PKGID2")
	)
	(segment
		(start 78.97114 -274.170902)
		(end 68.05168 -263.251442)
		(width 0.12954)
		(layer "B.Cu")
		(net "FM_CPU1_PKGID2")
	)
	(segment
		(start 85.882226 -274.170902)
		(end 84.128356 -274.170902)
		(width 0.0889)
		(layer "B.Cu")
		(net "FM_CPU1_PKGID2")
	)
	(segment
		(start 91.35745 -273.942556)
		(end 91.347036 -273.948652)
		(width 0.0889)
		(layer "B.Cu")
		(net "FM_CPU1_PKGID2")
	)
	(segment
		(start 42.595038 -252.60681)
		(end 42.595038 -192.95999)
		(width 0.12954)
		(layer "B.Cu")
		(net "FM_CPU1_PKGID2")
	)
	(segment
		(start 86.19998 -274.174458)
		(end 85.885782 -274.174458)
		(width 0.0889)
		(layer "B.Cu")
		(net "FM_CPU1_PKGID2")
	)
	(segment
		(start 52.12588 -189.169548)
		(end 52.12588 -187.086748)
		(width 0.12954)
		(layer "B.Cu")
		(net "FM_CPU1_PKGID2")
	)
	(segment
		(start 59.046364 -263.03097)
		(end 58.67273 -263.404604)
		(width 0.12954)
		(layer "B.Cu")
		(net "FM_CPU1_PKGID2")
	)
	(segment
		(start 96.056196 -273.942556)
		(end 96.041464 -273.951192)
		(width 0.0889)
		(layer "B.Cu")
		(net "FM_CPU1_PKGID2")
	)
	(segment
		(start 58.67273 -263.404604)
		(end 56.202072 -263.404604)
		(width 0.12954)
		(layer "B.Cu")
		(net "FM_CPU1_PKGID2")
	)
	(segment
		(start 107.339892 -270.683482)
		(end 107.333796 -270.687038)
		(width 0.0889)
		(layer "B.Cu")
		(net "FM_CPU1_PKGID2")
	)
	(segment
		(start 86.35619 -274.018248)
		(end 86.19998 -274.174458)
		(width 0.0889)
		(layer "B.Cu")
		(net "FM_CPU1_PKGID2")
	)
	(segment
		(start 42.595038 -192.95999)
		(end 44.48048 -191.074548)
		(width 0.12954)
		(layer "B.Cu")
		(net "FM_CPU1_PKGID2")
	)
	(segment
		(start 86.375748 -274.018248)
		(end 86.35619 -274.018248)
		(width 0.0889)
		(layer "B.Cu")
		(net "FM_CPU1_PKGID2")
	)
	(segment
		(start 109.400594 -267.755878)
		(end 109.113066 -268.043406)
		(width 0.0889)
		(layer "B.Cu")
		(net "FM_CPU1_PKGID2")
	)
	(segment
		(start 63.410338 -263.03097)
		(end 60.872878 -263.03097)
		(width 0.12954)
		(layer "B.Cu")
		(net "FM_CPU1_PKGID2")
	)
	(segment
		(start 102.640892 -273.939)
		(end 102.634796 -273.942556)
		(width 0.0889)
		(layer "B.Cu")
		(net "FM_CPU1_PKGID2")
	)
	(segment
		(start 99.815396 -273.942556)
		(end 99.800664 -273.951192)
		(width 0.0889)
		(layer "B.Cu")
		(net "FM_CPU1_PKGID2")
	)
	(segment
		(start 108.273596 -269.059152)
		(end 108.264706 -269.064232)
		(width 0.0889)
		(layer "B.Cu")
		(net "FM_CPU1_PKGID2")
	)
	(segment
		(start 53.402738 -260.060186)
		(end 53.402738 -258.30149)
		(width 0.12954)
		(layer "B.Cu")
		(net "FM_CPU1_PKGID2")
	)
	(segment
		(start 105.373678 -273.137376)
		(end 105.358946 -273.12874)
		(width 0.0889)
		(layer "B.Cu")
		(net "FM_CPU1_PKGID2")
	)
	(segment
		(start 108.775246 -268.043406)
		(end 108.441236 -268.377416)
		(width 0.0889)
		(layer "B.Cu")
		(net "FM_CPU1_PKGID2")
	)
	(segment
		(start 96.995996 -273.942556)
		(end 96.981264 -273.951192)
		(width 0.0889)
		(layer "B.Cu")
		(net "FM_CPU1_PKGID2")
	)
	(segment
		(start 55.26024 -261.917688)
		(end 53.402738 -260.060186)
		(width 0.12954)
		(layer "B.Cu")
		(net "FM_CPU1_PKGID2")
	)
	(segment
		(start 63.63081 -263.251442)
		(end 63.410338 -263.03097)
		(width 0.12954)
		(layer "B.Cu")
		(net "FM_CPU1_PKGID2")
	)
	(segment
		(start 108.441236 -268.377416)
		(end 108.441236 -268.911324)
		(width 0.0889)
		(layer "B.Cu")
		(net "FM_CPU1_PKGID2")
	)
	(segment
		(start 98.875596 -273.942556)
		(end 98.860864 -273.951192)
		(width 0.0889)
		(layer "B.Cu")
		(net "FM_CPU1_PKGID2")
	)
	(segment
		(start 107.80395 -269.873222)
		(end 107.79506 -269.878302)
		(width 0.0889)
		(layer "B.Cu")
		(net "FM_CPU1_PKGID2")
	)
	(arc
		(start 87.597996 -273.942556)
		(mid 87.315294 -274.018332)
		(end 87.032592 -273.942556)
		(width 0.0889)
		(layer "B.Cu")
		(net "FM_CPU1_PKGID2")
	)
	(arc
		(start 94.161864 -273.951192)
		(mid 93.885389 -274.018512)
		(end 93.611192 -273.942556)
		(width 0.0889)
		(layer "B.Cu")
		(net "FM_CPU1_PKGID2")
	)
	(arc
		(start 90.791792 -273.942556)
		(mid 90.604594 -273.892413)
		(end 90.417396 -273.942556)
		(width 0.0889)
		(layer "B.Cu")
		(net "FM_CPU1_PKGID2")
	)
	(arc
		(start 96.430592 -273.942556)
		(mid 96.243394 -273.892413)
		(end 96.056196 -273.942556)
		(width 0.0889)
		(layer "B.Cu")
		(net "FM_CPU1_PKGID2")
	)
	(arc
		(start 107.324906 -270.692118)
		(mid 107.193992 -270.828478)
		(end 107.146344 -271.011396)
		(width 0.0889)
		(layer "B.Cu")
		(net "FM_CPU1_PKGID2")
	)
	(arc
		(start 106.206544 -272.654776)
		(mid 106.127174 -272.92851)
		(end 105.92435 -273.12874)
		(width 0.0889)
		(layer "B.Cu")
		(net "FM_CPU1_PKGID2")
	)
	(arc
		(start 104.04475 -273.12874)
		(mid 103.767937 -273.20461)
		(end 103.489506 -273.134836)
		(width 0.0889)
		(layer "B.Cu")
		(net "FM_CPU1_PKGID2")
	)
	(arc
		(start 101.694996 -273.942556)
		(mid 101.412294 -274.018332)
		(end 101.129592 -273.942556)
		(width 0.0889)
		(layer "B.Cu")
		(net "FM_CPU1_PKGID2")
	)
	(arc
		(start 89.477596 -273.942556)
		(mid 89.194894 -274.018332)
		(end 88.912192 -273.942556)
		(width 0.0889)
		(layer "B.Cu")
		(net "FM_CPU1_PKGID2")
	)
	(arc
		(start 92.286582 -273.948652)
		(mid 92.008404 -274.018375)
		(end 91.731846 -273.942556)
		(width 0.0889)
		(layer "B.Cu")
		(net "FM_CPU1_PKGID2")
	)
	(arc
		(start 100.740464 -273.951192)
		(mid 100.463989 -274.018512)
		(end 100.189792 -273.942556)
		(width 0.0889)
		(layer "B.Cu")
		(net "FM_CPU1_PKGID2")
	)
	(arc
		(start 91.731846 -273.942556)
		(mid 91.544648 -273.892413)
		(end 91.35745 -273.942556)
		(width 0.0889)
		(layer "B.Cu")
		(net "FM_CPU1_PKGID2")
	)
	(arc
		(start 105.92435 -273.12874)
		(mid 105.650151 -273.204575)
		(end 105.373678 -273.137376)
		(width 0.0889)
		(layer "B.Cu")
		(net "FM_CPU1_PKGID2")
	)
	(arc
		(start 92.671392 -273.942556)
		(mid 92.484194 -273.892413)
		(end 92.296996 -273.942556)
		(width 0.0889)
		(layer "B.Cu")
		(net "FM_CPU1_PKGID2")
	)
	(arc
		(start 90.417396 -273.942556)
		(mid 90.134694 -274.018332)
		(end 89.851992 -273.942556)
		(width 0.0889)
		(layer "B.Cu")
		(net "FM_CPU1_PKGID2")
	)
	(arc
		(start 86.658196 -273.942556)
		(mid 86.521954 -273.99899)
		(end 86.375748 -274.018248)
		(width 0.0889)
		(layer "B.Cu")
		(net "FM_CPU1_PKGID2")
	)
	(arc
		(start 98.310192 -273.942556)
		(mid 98.122994 -273.892413)
		(end 97.935796 -273.942556)
		(width 0.0889)
		(layer "B.Cu")
		(net "FM_CPU1_PKGID2")
	)
	(arc
		(start 95.116396 -273.942556)
		(mid 94.833694 -274.018332)
		(end 94.550992 -273.942556)
		(width 0.0889)
		(layer "B.Cu")
		(net "FM_CPU1_PKGID2")
	)
	(arc
		(start 95.490792 -273.942556)
		(mid 95.303594 -273.892413)
		(end 95.116396 -273.942556)
		(width 0.0889)
		(layer "B.Cu")
		(net "FM_CPU1_PKGID2")
	)
	(arc
		(start 107.79506 -269.878302)
		(mid 107.664146 -270.014662)
		(end 107.616498 -270.19758)
		(width 0.0889)
		(layer "B.Cu")
		(net "FM_CPU1_PKGID2")
	)
	(arc
		(start 103.104696 -273.12874)
		(mid 102.969763 -273.262094)
		(end 102.917498 -273.444462)
		(width 0.0889)
		(layer "B.Cu")
		(net "FM_CPU1_PKGID2")
	)
	(arc
		(start 99.249992 -273.942556)
		(mid 99.062794 -273.892413)
		(end 98.875596 -273.942556)
		(width 0.0889)
		(layer "B.Cu")
		(net "FM_CPU1_PKGID2")
	)
	(arc
		(start 107.616498 -270.19758)
		(mid 107.542507 -270.477146)
		(end 107.339892 -270.683482)
		(width 0.0889)
		(layer "B.Cu")
		(net "FM_CPU1_PKGID2")
	)
	(arc
		(start 88.912192 -273.942556)
		(mid 88.724994 -273.892413)
		(end 88.537796 -273.942556)
		(width 0.0889)
		(layer "B.Cu")
		(net "FM_CPU1_PKGID2")
	)
	(arc
		(start 102.620064 -273.951192)
		(mid 102.343589 -274.018512)
		(end 102.069392 -273.942556)
		(width 0.0889)
		(layer "B.Cu")
		(net "FM_CPU1_PKGID2")
	)
	(arc
		(start 108.086144 -269.405608)
		(mid 108.005233 -269.675736)
		(end 107.80395 -269.873222)
		(width 0.0889)
		(layer "B.Cu")
		(net "FM_CPU1_PKGID2")
	)
	(arc
		(start 103.479092 -273.12874)
		(mid 103.291894 -273.078597)
		(end 103.104696 -273.12874)
		(width 0.0889)
		(layer "B.Cu")
		(net "FM_CPU1_PKGID2")
	)
	(arc
		(start 100.189792 -273.942556)
		(mid 100.002594 -273.892413)
		(end 99.815396 -273.942556)
		(width 0.0889)
		(layer "B.Cu")
		(net "FM_CPU1_PKGID2")
	)
	(arc
		(start 106.676698 -271.839436)
		(mid 106.597479 -272.114121)
		(end 106.393996 -272.314924)
		(width 0.0889)
		(layer "B.Cu")
		(net "FM_CPU1_PKGID2")
	)
	(arc
		(start 93.222064 -273.951192)
		(mid 92.945589 -274.018512)
		(end 92.671392 -273.942556)
		(width 0.0889)
		(layer "B.Cu")
		(net "FM_CPU1_PKGID2")
	)
	(arc
		(start 93.611192 -273.942556)
		(mid 93.423994 -273.892413)
		(end 93.236796 -273.942556)
		(width 0.0889)
		(layer "B.Cu")
		(net "FM_CPU1_PKGID2")
	)
	(arc
		(start 98.860864 -273.951192)
		(mid 98.584389 -274.018512)
		(end 98.310192 -273.942556)
		(width 0.0889)
		(layer "B.Cu")
		(net "FM_CPU1_PKGID2")
	)
	(arc
		(start 102.917498 -273.453098)
		(mid 102.843507 -273.732664)
		(end 102.640892 -273.939)
		(width 0.0889)
		(layer "B.Cu")
		(net "FM_CPU1_PKGID2")
	)
	(arc
		(start 108.441236 -268.911324)
		(mid 108.367444 -268.991277)
		(end 108.279692 -269.055596)
		(width 0.0889)
		(layer "B.Cu")
		(net "FM_CPU1_PKGID2")
	)
	(arc
		(start 87.032592 -273.942556)
		(mid 86.845394 -273.892413)
		(end 86.658196 -273.942556)
		(width 0.0889)
		(layer "B.Cu")
		(net "FM_CPU1_PKGID2")
	)
	(arc
		(start 104.419146 -273.12874)
		(mid 104.231948 -273.078597)
		(end 104.04475 -273.12874)
		(width 0.0889)
		(layer "B.Cu")
		(net "FM_CPU1_PKGID2")
	)
	(arc
		(start 87.972392 -273.942556)
		(mid 87.785194 -273.892413)
		(end 87.597996 -273.942556)
		(width 0.0889)
		(layer "B.Cu")
		(net "FM_CPU1_PKGID2")
	)
	(arc
		(start 104.98455 -273.12874)
		(mid 104.710351 -273.204575)
		(end 104.433878 -273.137376)
		(width 0.0889)
		(layer "B.Cu")
		(net "FM_CPU1_PKGID2")
	)
	(arc
		(start 96.981264 -273.951192)
		(mid 96.704789 -274.018512)
		(end 96.430592 -273.942556)
		(width 0.0889)
		(layer "B.Cu")
		(net "FM_CPU1_PKGID2")
	)
	(arc
		(start 94.550992 -273.942556)
		(mid 94.363794 -273.892413)
		(end 94.176596 -273.942556)
		(width 0.0889)
		(layer "B.Cu")
		(net "FM_CPU1_PKGID2")
	)
	(arc
		(start 89.851992 -273.942556)
		(mid 89.664794 -273.892413)
		(end 89.477596 -273.942556)
		(width 0.0889)
		(layer "B.Cu")
		(net "FM_CPU1_PKGID2")
	)
	(arc
		(start 99.800664 -273.951192)
		(mid 99.524189 -274.018512)
		(end 99.249992 -273.942556)
		(width 0.0889)
		(layer "B.Cu")
		(net "FM_CPU1_PKGID2")
	)
	(arc
		(start 105.358946 -273.12874)
		(mid 105.171748 -273.078597)
		(end 104.98455 -273.12874)
		(width 0.0889)
		(layer "B.Cu")
		(net "FM_CPU1_PKGID2")
	)
	(arc
		(start 88.537796 -273.942556)
		(mid 88.255094 -274.018332)
		(end 87.972392 -273.942556)
		(width 0.0889)
		(layer "B.Cu")
		(net "FM_CPU1_PKGID2")
	)
	(arc
		(start 106.85526 -271.505934)
		(mid 106.724346 -271.642294)
		(end 106.676698 -271.825212)
		(width 0.0889)
		(layer "B.Cu")
		(net "FM_CPU1_PKGID2")
	)
	(arc
		(start 97.921064 -273.951192)
		(mid 97.644589 -274.018512)
		(end 97.370392 -273.942556)
		(width 0.0889)
		(layer "B.Cu")
		(net "FM_CPU1_PKGID2")
	)
	(arc
		(start 97.370392 -273.942556)
		(mid 97.183194 -273.892413)
		(end 96.995996 -273.942556)
		(width 0.0889)
		(layer "B.Cu")
		(net "FM_CPU1_PKGID2")
	)
	(arc
		(start 101.129592 -273.942556)
		(mid 100.942394 -273.892413)
		(end 100.755196 -273.942556)
		(width 0.0889)
		(layer "B.Cu")
		(net "FM_CPU1_PKGID2")
	)
	(arc
		(start 106.385106 -272.320004)
		(mid 106.254192 -272.456364)
		(end 106.206544 -272.639282)
		(width 0.0889)
		(layer "B.Cu")
		(net "FM_CPU1_PKGID2")
	)
	(arc
		(start 102.069392 -273.942556)
		(mid 101.882194 -273.892413)
		(end 101.694996 -273.942556)
		(width 0.0889)
		(layer "B.Cu")
		(net "FM_CPU1_PKGID2")
	)
	(arc
		(start 91.347036 -273.948652)
		(mid 91.068604 -274.018498)
		(end 90.791792 -273.942556)
		(width 0.0889)
		(layer "B.Cu")
		(net "FM_CPU1_PKGID2")
	)
	(arc
		(start 107.146344 -271.02689)
		(mid 107.066974 -271.300624)
		(end 106.86415 -271.500854)
		(width 0.0889)
		(layer "B.Cu")
		(net "FM_CPU1_PKGID2")
	)
	(arc
		(start 108.264706 -269.064232)
		(mid 108.133792 -269.200592)
		(end 108.086144 -269.38351)
		(width 0.0889)
		(layer "B.Cu")
		(net "FM_CPU1_PKGID2")
	)
	(arc
		(start 96.041464 -273.951192)
		(mid 95.764989 -274.018512)
		(end 95.490792 -273.942556)
		(width 0.0889)
		(layer "B.Cu")
		(net "FM_CPU1_PKGID2")
	)
	(segment
		(start 184.71896 -129.256028)
		(end 184.3532 -128.890268)
		(width 0.127)
		(layer "In2.Cu")
		(net "FM_CPU1_PKGID2")
	)
	(segment
		(start 184.3532 -127.104648)
		(end 181.7878 -124.539248)
		(width 0.127)
		(layer "In2.Cu")
		(net "FM_CPU1_PKGID2")
	)
	(segment
		(start 181.7878 -122.908568)
		(end 180.955696 -122.076464)
		(width 0.127)
		(layer "In2.Cu")
		(net "FM_CPU1_PKGID2")
	)
	(segment
		(start 181.7878 -124.539248)
		(end 181.7878 -122.908568)
		(width 0.127)
		(layer "In2.Cu")
		(net "FM_CPU1_PKGID2")
	)
	(segment
		(start 185.22188 -129.256028)
		(end 184.71896 -129.256028)
		(width 0.127)
		(layer "In2.Cu")
		(net "FM_CPU1_PKGID2")
	)
	(segment
		(start 180.955696 -122.076464)
		(end 180.955696 -120.575578)
		(width 0.127)
		(layer "In2.Cu")
		(net "FM_CPU1_PKGID2")
	)
	(segment
		(start 184.3532 -128.890268)
		(end 184.3532 -127.104648)
		(width 0.127)
		(layer "In2.Cu")
		(net "FM_CPU1_PKGID2")
	)
	(segment
		(start 65.734946 -186.832748)
		(end 57.96788 -186.832748)
		(width 0.127)
		(layer "In4.Cu")
		(net "FM_CPU1_PKGID2")
	)
	(segment
		(start 181.36108 -132.933948)
		(end 180.48478 -133.810248)
		(width 0.127)
		(layer "In4.Cu")
		(net "FM_CPU1_PKGID2")
	)
	(segment
		(start 166.729664 -134.838948)
		(end 142.682722 -134.838948)
		(width 0.127)
		(layer "In4.Cu")
		(net "FM_CPU1_PKGID2")
	)
	(segment
		(start 68.859146 -183.708548)
		(end 65.734946 -186.832748)
		(width 0.127)
		(layer "In4.Cu")
		(net "FM_CPU1_PKGID2")
	)
	(segment
		(start 185.22188 -129.256028)
		(end 184.45988 -130.018028)
		(width 0.127)
		(layer "In4.Cu")
		(net "FM_CPU1_PKGID2")
	)
	(segment
		(start 57.96788 -186.832748)
		(end 57.71388 -187.086748)
		(width 0.127)
		(layer "In4.Cu")
		(net "FM_CPU1_PKGID2")
	)
	(segment
		(start 110.438184 -149.194774)
		(end 75.89901 -183.733948)
		(width 0.127)
		(layer "In4.Cu")
		(net "FM_CPU1_PKGID2")
	)
	(segment
		(start 180.48478 -133.810248)
		(end 169.21353 -133.810248)
		(width 0.127)
		(layer "In4.Cu")
		(net "FM_CPU1_PKGID2")
	)
	(segment
		(start 75.038712 -183.733948)
		(end 74.60488 -183.300116)
		(width 0.127)
		(layer "In4.Cu")
		(net "FM_CPU1_PKGID2")
	)
	(segment
		(start 74.60488 -183.300116)
		(end 70.055232 -183.300116)
		(width 0.127)
		(layer "In4.Cu")
		(net "FM_CPU1_PKGID2")
	)
	(segment
		(start 75.89901 -183.733948)
		(end 75.038712 -183.733948)
		(width 0.127)
		(layer "In4.Cu")
		(net "FM_CPU1_PKGID2")
	)
	(segment
		(start 128.326896 -149.194774)
		(end 110.438184 -149.194774)
		(width 0.127)
		(layer "In4.Cu")
		(net "FM_CPU1_PKGID2")
	)
	(segment
		(start 183.82488 -132.933948)
		(end 181.36108 -132.933948)
		(width 0.127)
		(layer "In4.Cu")
		(net "FM_CPU1_PKGID2")
	)
	(segment
		(start 184.45988 -132.298948)
		(end 183.82488 -132.933948)
		(width 0.127)
		(layer "In4.Cu")
		(net "FM_CPU1_PKGID2")
	)
	(segment
		(start 70.055232 -183.300116)
		(end 69.6468 -183.708548)
		(width 0.127)
		(layer "In4.Cu")
		(net "FM_CPU1_PKGID2")
	)
	(segment
		(start 184.45988 -130.018028)
		(end 184.45988 -132.298948)
		(width 0.127)
		(layer "In4.Cu")
		(net "FM_CPU1_PKGID2")
	)
	(segment
		(start 57.71388 -187.086748)
		(end 52.12588 -187.086748)
		(width 0.127)
		(layer "In4.Cu")
		(net "FM_CPU1_PKGID2")
	)
	(segment
		(start 69.6468 -183.708548)
		(end 68.859146 -183.708548)
		(width 0.127)
		(layer "In4.Cu")
		(net "FM_CPU1_PKGID2")
	)
	(segment
		(start 142.682722 -134.838948)
		(end 128.326896 -149.194774)
		(width 0.127)
		(layer "In4.Cu")
		(net "FM_CPU1_PKGID2")
	)
	(segment
		(start 169.21353 -133.810248)
		(end 166.729664 -134.838948)
		(width 0.127)
		(layer "In4.Cu")
		(net "FM_CPU1_PKGID2")
	)
	(segment
		(start 180.39588 -121.93524)
		(end 180.555646 -121.775474)
		(width 0.12954)
		(layer "F.Cu")
		(net "FM_CPU1_PKGID1")
	)
	(segment
		(start 181.38648 -127.301498)
		(end 180.64988 -126.564898)
		(width 0.12954)
		(layer "F.Cu")
		(net "FM_CPU1_PKGID1")
	)
	(segment
		(start 180.52288 -132.425948)
		(end 181.38648 -131.562348)
		(width 0.12954)
		(layer "F.Cu")
		(net "FM_CPU1_PKGID1")
	)
	(segment
		(start 103.291894 -266.941554)
		(end 103.292148 -266.941808)
		(width 0.12954)
		(layer "F.Cu")
		(net "FM_CPU1_PKGID1")
	)
	(segment
		(start 103.291894 -266.405868)
		(end 103.291894 -266.941554)
		(width 0.12954)
		(layer "F.Cu")
		(net "FM_CPU1_PKGID1")
	)
	(segment
		(start 180.39588 -125.095762)
		(end 180.39588 -121.93524)
		(width 0.12954)
		(layer "F.Cu")
		(net "FM_CPU1_PKGID1")
	)
	(segment
		(start 180.64988 -126.564898)
		(end 180.641498 -126.556516)
		(width 0.12954)
		(layer "F.Cu")
		(net "FM_CPU1_PKGID1")
	)
	(segment
		(start 180.641498 -126.556516)
		(end 180.641498 -125.34138)
		(width 0.12954)
		(layer "F.Cu")
		(net "FM_CPU1_PKGID1")
	)
	(segment
		(start 180.641498 -125.34138)
		(end 180.39588 -125.095762)
		(width 0.12954)
		(layer "F.Cu")
		(net "FM_CPU1_PKGID1")
	)
	(segment
		(start 181.38648 -131.562348)
		(end 181.38648 -127.301498)
		(width 0.12954)
		(layer "F.Cu")
		(net "FM_CPU1_PKGID1")
	)
	(via
		(at 103.292148 -266.941808)
		(size 0.4572)
		(drill 0.2032)
		(layers "F.Cu" "B.Cu")
		(net "FM_CPU1_PKGID1")
	)
	(via
		(at 180.641498 -125.34138)
		(size 0.762)
		(drill 0.381)
		(layers "F.Cu" "B.Cu")
		(net "FM_CPU1_PKGID1")
	)
	(via
		(at 180.52288 -132.425948)
		(size 0.508)
		(drill 0.254)
		(layers "F.Cu" "B.Cu")
		(net "FM_CPU1_PKGID1")
	)
	(via
		(at 53.26888 -185.892948)
		(size 0.508)
		(drill 0.254)
		(layers "F.Cu" "B.Cu")
		(net "FM_CPU1_PKGID1")
	)
	(via
		(at 68.574158 -245.13667)
		(size 0.6604)
		(drill 0.3302)
		(layers "F.Cu" "B.Cu")
		(net "FM_CPU1_PKGID1")
	)
	(segment
		(start 52.790598 -198.350124)
		(end 55.038498 -196.102224)
		(width 0.12954)
		(layer "B.Cu")
		(net "FM_CPU1_PKGID1")
	)
	(segment
		(start 101.694996 -266.45235)
		(end 101.680264 -266.443714)
		(width 0.0889)
		(layer "B.Cu")
		(net "FM_CPU1_PKGID1")
	)
	(segment
		(start 69.62267 -245.13667)
		(end 68.574158 -245.13667)
		(width 0.12954)
		(layer "B.Cu")
		(net "FM_CPU1_PKGID1")
	)
	(segment
		(start 54.461918 -194.44589)
		(end 54.461918 -191.82461)
		(width 0.12954)
		(layer "B.Cu")
		(net "FM_CPU1_PKGID1")
	)
	(segment
		(start 68.574158 -245.13667)
		(end 63.204344 -245.13667)
		(width 0.12954)
		(layer "B.Cu")
		(net "FM_CPU1_PKGID1")
	)
	(segment
		(start 98.875596 -266.45235)
		(end 98.860864 -266.443714)
		(width 0.0889)
		(layer "B.Cu")
		(net "FM_CPU1_PKGID1")
	)
	(segment
		(start 52.790598 -238.20501)
		(end 52.790598 -198.350124)
		(width 0.12954)
		(layer "B.Cu")
		(net "FM_CPU1_PKGID1")
	)
	(segment
		(start 102.634796 -266.45235)
		(end 102.634542 -266.45235)
		(width 0.0889)
		(layer "B.Cu")
		(net "FM_CPU1_PKGID1")
	)
	(segment
		(start 54.461918 -191.82461)
		(end 53.11648 -190.479172)
		(width 0.12954)
		(layer "B.Cu")
		(net "FM_CPU1_PKGID1")
	)
	(segment
		(start 62.531244 -244.46357)
		(end 60.910978 -244.46357)
		(width 0.12954)
		(layer "B.Cu")
		(net "FM_CPU1_PKGID1")
	)
	(segment
		(start 55.038498 -195.02247)
		(end 54.461918 -194.44589)
		(width 0.12954)
		(layer "B.Cu")
		(net "FM_CPU1_PKGID1")
	)
	(segment
		(start 73.478898 -259.372354)
		(end 72.298306 -258.191762)
		(width 0.12954)
		(layer "B.Cu")
		(net "FM_CPU1_PKGID1")
	)
	(segment
		(start 85.9282 -267.11021)
		(end 79.623158 -267.11021)
		(width 0.12954)
		(layer "B.Cu")
		(net "FM_CPU1_PKGID1")
	)
	(segment
		(start 92.216478 -267.25753)
		(end 92.201746 -267.266166)
		(width 0.0889)
		(layer "B.Cu")
		(net "FM_CPU1_PKGID1")
	)
	(segment
		(start 63.204344 -245.13667)
		(end 62.531244 -244.46357)
		(width 0.12954)
		(layer "B.Cu")
		(net "FM_CPU1_PKGID1")
	)
	(segment
		(start 79.623158 -267.11021)
		(end 73.478898 -260.96595)
		(width 0.12954)
		(layer "B.Cu")
		(net "FM_CPU1_PKGID1")
	)
	(segment
		(start 93.156278 -267.25753)
		(end 93.141546 -267.266166)
		(width 0.0889)
		(layer "B.Cu")
		(net "FM_CPU1_PKGID1")
	)
	(segment
		(start 73.478898 -260.96595)
		(end 73.478898 -259.372354)
		(width 0.12954)
		(layer "B.Cu")
		(net "FM_CPU1_PKGID1")
	)
	(segment
		(start 95.975678 -267.25753)
		(end 95.960946 -267.266166)
		(width 0.0889)
		(layer "B.Cu")
		(net "FM_CPU1_PKGID1")
	)
	(segment
		(start 59.03468 -243.296948)
		(end 56.772302 -241.03457)
		(width 0.12954)
		(layer "B.Cu")
		(net "FM_CPU1_PKGID1")
	)
	(segment
		(start 90.887296 -267.266166)
		(end 90.872564 -267.25753)
		(width 0.0889)
		(layer "B.Cu")
		(net "FM_CPU1_PKGID1")
	)
	(segment
		(start 53.11648 -186.045348)
		(end 53.26888 -185.892948)
		(width 0.12954)
		(layer "B.Cu")
		(net "FM_CPU1_PKGID1")
	)
	(segment
		(start 56.772302 -241.03457)
		(end 55.620158 -241.03457)
		(width 0.12954)
		(layer "B.Cu")
		(net "FM_CPU1_PKGID1")
	)
	(segment
		(start 60.910978 -244.46357)
		(end 59.744356 -243.296948)
		(width 0.12954)
		(layer "B.Cu")
		(net "FM_CPU1_PKGID1")
	)
	(segment
		(start 98.310192 -266.45235)
		(end 98.304096 -266.455906)
		(width 0.0889)
		(layer "B.Cu")
		(net "FM_CPU1_PKGID1")
	)
	(segment
		(start 95.035878 -267.25753)
		(end 95.021146 -267.266166)
		(width 0.0889)
		(layer "B.Cu")
		(net "FM_CPU1_PKGID1")
	)
	(segment
		(start 86.134956 -267.316966)
		(end 85.9282 -267.11021)
		(width 0.12954)
		(layer "B.Cu")
		(net "FM_CPU1_PKGID1")
	)
	(segment
		(start 103.292148 -266.941808)
		(end 102.634796 -266.45235)
		(width 0.0889)
		(layer "B.Cu")
		(net "FM_CPU1_PKGID1")
	)
	(segment
		(start 97.465896 -267.266166)
		(end 97.455482 -267.26007)
		(width 0.0889)
		(layer "B.Cu")
		(net "FM_CPU1_PKGID1")
	)
	(segment
		(start 72.298306 -247.812306)
		(end 69.62267 -245.13667)
		(width 0.12954)
		(layer "B.Cu")
		(net "FM_CPU1_PKGID1")
	)
	(segment
		(start 59.744356 -243.296948)
		(end 59.03468 -243.296948)
		(width 0.12954)
		(layer "B.Cu")
		(net "FM_CPU1_PKGID1")
	)
	(segment
		(start 100.755196 -266.45235)
		(end 100.740464 -266.443714)
		(width 0.0889)
		(layer "B.Cu")
		(net "FM_CPU1_PKGID1")
	)
	(segment
		(start 97.849182 -267.261086)
		(end 97.840292 -267.266166)
		(width 0.0889)
		(layer "B.Cu")
		(net "FM_CPU1_PKGID1")
	)
	(segment
		(start 55.620158 -241.03457)
		(end 52.790598 -238.20501)
		(width 0.12954)
		(layer "B.Cu")
		(net "FM_CPU1_PKGID1")
	)
	(segment
		(start 53.11648 -190.479172)
		(end 53.11648 -186.045348)
		(width 0.12954)
		(layer "B.Cu")
		(net "FM_CPU1_PKGID1")
	)
	(segment
		(start 55.038498 -196.102224)
		(end 55.038498 -195.02247)
		(width 0.12954)
		(layer "B.Cu")
		(net "FM_CPU1_PKGID1")
	)
	(segment
		(start 72.298306 -258.191762)
		(end 72.298306 -247.812306)
		(width 0.12954)
		(layer "B.Cu")
		(net "FM_CPU1_PKGID1")
	)
	(segment
		(start 99.815396 -266.45235)
		(end 99.800664 -266.443714)
		(width 0.0889)
		(layer "B.Cu")
		(net "FM_CPU1_PKGID1")
	)
	(segment
		(start 87.315294 -267.316966)
		(end 86.134956 -267.316966)
		(width 0.0889)
		(layer "B.Cu")
		(net "FM_CPU1_PKGID1")
	)
	(segment
		(start 94.096078 -267.25753)
		(end 94.081346 -267.266166)
		(width 0.0889)
		(layer "B.Cu")
		(net "FM_CPU1_PKGID1")
	)
	(segment
		(start 91.272106 -267.26007)
		(end 91.261692 -267.266166)
		(width 0.0889)
		(layer "B.Cu")
		(net "FM_CPU1_PKGID1")
	)
	(arc
		(start 92.76715 -267.266166)
		(mid 92.492921 -267.190241)
		(end 92.216478 -267.25753)
		(width 0.0889)
		(layer "B.Cu")
		(net "FM_CPU1_PKGID1")
	)
	(arc
		(start 91.261692 -267.266166)
		(mid 91.074494 -267.316309)
		(end 90.887296 -267.266166)
		(width 0.0889)
		(layer "B.Cu")
		(net "FM_CPU1_PKGID1")
	)
	(arc
		(start 89.007696 -267.266166)
		(mid 88.724994 -267.190424)
		(end 88.442292 -267.266166)
		(width 0.0889)
		(layer "B.Cu")
		(net "FM_CPU1_PKGID1")
	)
	(arc
		(start 97.455482 -267.26007)
		(mid 97.177304 -267.190378)
		(end 96.900746 -267.266166)
		(width 0.0889)
		(layer "B.Cu")
		(net "FM_CPU1_PKGID1")
	)
	(arc
		(start 88.442292 -267.266166)
		(mid 88.255094 -267.316309)
		(end 88.067896 -267.266166)
		(width 0.0889)
		(layer "B.Cu")
		(net "FM_CPU1_PKGID1")
	)
	(arc
		(start 89.947496 -267.266166)
		(mid 89.664794 -267.190424)
		(end 89.382092 -267.266166)
		(width 0.0889)
		(layer "B.Cu")
		(net "FM_CPU1_PKGID1")
	)
	(arc
		(start 89.382092 -267.266166)
		(mid 89.194894 -267.316309)
		(end 89.007696 -267.266166)
		(width 0.0889)
		(layer "B.Cu")
		(net "FM_CPU1_PKGID1")
	)
	(arc
		(start 98.027744 -266.941808)
		(mid 97.980065 -267.124708)
		(end 97.849182 -267.261086)
		(width 0.0889)
		(layer "B.Cu")
		(net "FM_CPU1_PKGID1")
	)
	(arc
		(start 92.201746 -267.266166)
		(mid 92.014548 -267.316309)
		(end 91.82735 -267.266166)
		(width 0.0889)
		(layer "B.Cu")
		(net "FM_CPU1_PKGID1")
	)
	(arc
		(start 95.021146 -267.266166)
		(mid 94.833948 -267.316309)
		(end 94.64675 -267.266166)
		(width 0.0889)
		(layer "B.Cu")
		(net "FM_CPU1_PKGID1")
	)
	(arc
		(start 102.634542 -266.45235)
		(mid 102.351984 -266.376667)
		(end 102.069392 -266.45235)
		(width 0.0889)
		(layer "B.Cu")
		(net "FM_CPU1_PKGID1")
	)
	(arc
		(start 88.067896 -267.266166)
		(mid 87.785194 -267.190424)
		(end 87.502492 -267.266166)
		(width 0.0889)
		(layer "B.Cu")
		(net "FM_CPU1_PKGID1")
	)
	(arc
		(start 102.069392 -266.45235)
		(mid 101.882194 -266.502527)
		(end 101.694996 -266.45235)
		(width 0.0889)
		(layer "B.Cu")
		(net "FM_CPU1_PKGID1")
	)
	(arc
		(start 91.82735 -267.266166)
		(mid 91.550537 -267.19033)
		(end 91.272106 -267.26007)
		(width 0.0889)
		(layer "B.Cu")
		(net "FM_CPU1_PKGID1")
	)
	(arc
		(start 87.502492 -267.266166)
		(mid 87.412236 -267.303888)
		(end 87.315294 -267.316966)
		(width 0.0889)
		(layer "B.Cu")
		(net "FM_CPU1_PKGID1")
	)
	(arc
		(start 90.872564 -267.25753)
		(mid 90.596123 -267.190364)
		(end 90.321892 -267.266166)
		(width 0.0889)
		(layer "B.Cu")
		(net "FM_CPU1_PKGID1")
	)
	(arc
		(start 97.840292 -267.266166)
		(mid 97.653094 -267.316309)
		(end 97.465896 -267.266166)
		(width 0.0889)
		(layer "B.Cu")
		(net "FM_CPU1_PKGID1")
	)
	(arc
		(start 93.70695 -267.266166)
		(mid 93.432721 -267.190241)
		(end 93.156278 -267.25753)
		(width 0.0889)
		(layer "B.Cu")
		(net "FM_CPU1_PKGID1")
	)
	(arc
		(start 98.304096 -266.455906)
		(mid 98.101683 -266.662319)
		(end 98.027744 -266.941808)
		(width 0.0889)
		(layer "B.Cu")
		(net "FM_CPU1_PKGID1")
	)
	(arc
		(start 100.740464 -266.443714)
		(mid 100.463989 -266.376394)
		(end 100.189792 -266.45235)
		(width 0.0889)
		(layer "B.Cu")
		(net "FM_CPU1_PKGID1")
	)
	(arc
		(start 90.321892 -267.266166)
		(mid 90.134694 -267.316309)
		(end 89.947496 -267.266166)
		(width 0.0889)
		(layer "B.Cu")
		(net "FM_CPU1_PKGID1")
	)
	(arc
		(start 101.129592 -266.45235)
		(mid 100.942394 -266.502527)
		(end 100.755196 -266.45235)
		(width 0.0889)
		(layer "B.Cu")
		(net "FM_CPU1_PKGID1")
	)
	(arc
		(start 98.860864 -266.443714)
		(mid 98.584389 -266.376394)
		(end 98.310192 -266.45235)
		(width 0.0889)
		(layer "B.Cu")
		(net "FM_CPU1_PKGID1")
	)
	(arc
		(start 94.081346 -267.266166)
		(mid 93.894148 -267.316309)
		(end 93.70695 -267.266166)
		(width 0.0889)
		(layer "B.Cu")
		(net "FM_CPU1_PKGID1")
	)
	(arc
		(start 93.141546 -267.266166)
		(mid 92.954348 -267.316309)
		(end 92.76715 -267.266166)
		(width 0.0889)
		(layer "B.Cu")
		(net "FM_CPU1_PKGID1")
	)
	(arc
		(start 96.900746 -267.266166)
		(mid 96.713548 -267.316309)
		(end 96.52635 -267.266166)
		(width 0.0889)
		(layer "B.Cu")
		(net "FM_CPU1_PKGID1")
	)
	(arc
		(start 95.960946 -267.266166)
		(mid 95.773748 -267.316309)
		(end 95.58655 -267.266166)
		(width 0.0889)
		(layer "B.Cu")
		(net "FM_CPU1_PKGID1")
	)
	(arc
		(start 100.189792 -266.45235)
		(mid 100.002594 -266.502493)
		(end 99.815396 -266.45235)
		(width 0.0889)
		(layer "B.Cu")
		(net "FM_CPU1_PKGID1")
	)
	(arc
		(start 95.58655 -267.266166)
		(mid 95.312321 -267.190241)
		(end 95.035878 -267.25753)
		(width 0.0889)
		(layer "B.Cu")
		(net "FM_CPU1_PKGID1")
	)
	(arc
		(start 99.249992 -266.45235)
		(mid 99.062794 -266.502493)
		(end 98.875596 -266.45235)
		(width 0.0889)
		(layer "B.Cu")
		(net "FM_CPU1_PKGID1")
	)
	(arc
		(start 101.680264 -266.443714)
		(mid 101.403789 -266.376394)
		(end 101.129592 -266.45235)
		(width 0.0889)
		(layer "B.Cu")
		(net "FM_CPU1_PKGID1")
	)
	(arc
		(start 94.64675 -267.266166)
		(mid 94.372521 -267.190241)
		(end 94.096078 -267.25753)
		(width 0.0889)
		(layer "B.Cu")
		(net "FM_CPU1_PKGID1")
	)
	(arc
		(start 99.800664 -266.443714)
		(mid 99.524189 -266.376394)
		(end 99.249992 -266.45235)
		(width 0.0889)
		(layer "B.Cu")
		(net "FM_CPU1_PKGID1")
	)
	(arc
		(start 96.52635 -267.266166)
		(mid 96.252121 -267.190241)
		(end 95.975678 -267.25753)
		(width 0.0889)
		(layer "B.Cu")
		(net "FM_CPU1_PKGID1")
	)
	(segment
		(start 172.09008 -132.095748)
		(end 172.09008 -131.079748)
		(width 0.127)
		(layer "In4.Cu")
		(net "FM_CPU1_PKGID1")
	)
	(segment
		(start 163.09721 -133.975348)
		(end 142.324582 -133.975348)
		(width 0.127)
		(layer "In4.Cu")
		(net "FM_CPU1_PKGID1")
	)
	(segment
		(start 69.1134 -182.794148)
		(end 66.73215 -182.794148)
		(width 0.127)
		(layer "In4.Cu")
		(net "FM_CPU1_PKGID1")
	)
	(segment
		(start 163.899088 -133.17347)
		(end 163.09721 -133.975348)
		(width 0.127)
		(layer "In4.Cu")
		(net "FM_CPU1_PKGID1")
	)
	(segment
		(start 179.96408 -131.867148)
		(end 178.03368 -131.867148)
		(width 0.127)
		(layer "In4.Cu")
		(net "FM_CPU1_PKGID1")
	)
	(segment
		(start 74.041254 -182.413148)
		(end 69.4944 -182.413148)
		(width 0.127)
		(layer "In4.Cu")
		(net "FM_CPU1_PKGID1")
	)
	(segment
		(start 172.87748 -132.883148)
		(end 172.09008 -132.095748)
		(width 0.127)
		(layer "In4.Cu")
		(net "FM_CPU1_PKGID1")
	)
	(segment
		(start 171.70908 -130.698748)
		(end 168.48455 -130.698748)
		(width 0.127)
		(layer "In4.Cu")
		(net "FM_CPU1_PKGID1")
	)
	(segment
		(start 177.01768 -132.883148)
		(end 172.87748 -132.883148)
		(width 0.127)
		(layer "In4.Cu")
		(net "FM_CPU1_PKGID1")
	)
	(segment
		(start 166.009828 -133.17347)
		(end 163.899088 -133.17347)
		(width 0.127)
		(layer "In4.Cu")
		(net "FM_CPU1_PKGID1")
	)
	(segment
		(start 53.34508 -185.969148)
		(end 53.26888 -185.892948)
		(width 0.127)
		(layer "In4.Cu")
		(net "FM_CPU1_PKGID1")
	)
	(segment
		(start 69.4944 -182.413148)
		(end 69.1134 -182.794148)
		(width 0.127)
		(layer "In4.Cu")
		(net "FM_CPU1_PKGID1")
	)
	(segment
		(start 66.73215 -182.794148)
		(end 63.55715 -185.969148)
		(width 0.127)
		(layer "In4.Cu")
		(net "FM_CPU1_PKGID1")
	)
	(segment
		(start 168.48455 -130.698748)
		(end 166.009828 -133.17347)
		(width 0.127)
		(layer "In4.Cu")
		(net "FM_CPU1_PKGID1")
	)
	(segment
		(start 127.968756 -148.331174)
		(end 110.080044 -148.331174)
		(width 0.127)
		(layer "In4.Cu")
		(net "FM_CPU1_PKGID1")
	)
	(segment
		(start 75.212702 -181.2417)
		(end 74.041254 -182.413148)
		(width 0.127)
		(layer "In4.Cu")
		(net "FM_CPU1_PKGID1")
	)
	(segment
		(start 110.080044 -148.331174)
		(end 77.169518 -181.2417)
		(width 0.127)
		(layer "In4.Cu")
		(net "FM_CPU1_PKGID1")
	)
	(segment
		(start 178.03368 -131.867148)
		(end 177.01768 -132.883148)
		(width 0.127)
		(layer "In4.Cu")
		(net "FM_CPU1_PKGID1")
	)
	(segment
		(start 142.324582 -133.975348)
		(end 127.968756 -148.331174)
		(width 0.127)
		(layer "In4.Cu")
		(net "FM_CPU1_PKGID1")
	)
	(segment
		(start 172.09008 -131.079748)
		(end 171.70908 -130.698748)
		(width 0.127)
		(layer "In4.Cu")
		(net "FM_CPU1_PKGID1")
	)
	(segment
		(start 63.55715 -185.969148)
		(end 53.34508 -185.969148)
		(width 0.127)
		(layer "In4.Cu")
		(net "FM_CPU1_PKGID1")
	)
	(segment
		(start 180.52288 -132.425948)
		(end 179.96408 -131.867148)
		(width 0.127)
		(layer "In4.Cu")
		(net "FM_CPU1_PKGID1")
	)
	(segment
		(start 77.169518 -181.2417)
		(end 75.212702 -181.2417)
		(width 0.127)
		(layer "In4.Cu")
		(net "FM_CPU1_PKGID1")
	)
	(segment
		(start 185.98896 -131.404868)
		(end 184.96788 -132.425948)
		(width 0.12954)
		(layer "F.Cu")
		(net "FM_CPU1_PKGID0")
	)
	(segment
		(start 185.22188 -126.564898)
		(end 185.98896 -127.331978)
		(width 0.12954)
		(layer "F.Cu")
		(net "FM_CPU1_PKGID0")
	)
	(segment
		(start 181.74462 -121.364248)
		(end 181.74462 -122.202702)
		(width 0.12954)
		(layer "F.Cu")
		(net "FM_CPU1_PKGID0")
	)
	(segment
		(start 184.705498 -125.16358)
		(end 184.705498 -125.34138)
		(width 0.12954)
		(layer "F.Cu")
		(net "FM_CPU1_PKGID0")
	)
	(segment
		(start 108.460794 -267.220192)
		(end 108.460794 -267.755878)
		(width 0.12954)
		(layer "F.Cu")
		(net "FM_CPU1_PKGID0")
	)
	(segment
		(start 181.74462 -122.202702)
		(end 184.705498 -125.16358)
		(width 0.12954)
		(layer "F.Cu")
		(net "FM_CPU1_PKGID0")
	)
	(segment
		(start 185.22188 -125.857762)
		(end 185.22188 -126.564898)
		(width 0.12954)
		(layer "F.Cu")
		(net "FM_CPU1_PKGID0")
	)
	(segment
		(start 185.98896 -127.331978)
		(end 185.98896 -131.404868)
		(width 0.12954)
		(layer "F.Cu")
		(net "FM_CPU1_PKGID0")
	)
	(segment
		(start 181.355746 -120.975374)
		(end 181.74462 -121.364248)
		(width 0.12954)
		(layer "F.Cu")
		(net "FM_CPU1_PKGID0")
	)
	(segment
		(start 108.461048 -267.219938)
		(end 108.460794 -267.220192)
		(width 0.12954)
		(layer "F.Cu")
		(net "FM_CPU1_PKGID0")
	)
	(segment
		(start 184.705498 -125.34138)
		(end 185.22188 -125.857762)
		(width 0.12954)
		(layer "F.Cu")
		(net "FM_CPU1_PKGID0")
	)
	(via
		(at 184.96788 -132.425948)
		(size 0.508)
		(drill 0.254)
		(layers "F.Cu" "B.Cu")
		(net "FM_CPU1_PKGID0")
	)
	(via
		(at 52.61356 -187.569348)
		(size 0.508)
		(drill 0.254)
		(layers "F.Cu" "B.Cu")
		(net "FM_CPU1_PKGID0")
	)
	(via
		(at 70.251828 -264.388346)
		(size 0.6604)
		(drill 0.3302)
		(layers "F.Cu" "B.Cu")
		(net "FM_CPU1_PKGID0")
	)
	(via
		(at 108.460794 -267.755878)
		(size 0.4572)
		(drill 0.2032)
		(layers "F.Cu" "B.Cu")
		(net "FM_CPU1_PKGID0")
	)
	(via
		(at 184.705498 -125.34138)
		(size 0.762)
		(drill 0.381)
		(layers "F.Cu" "B.Cu")
		(net "FM_CPU1_PKGID0")
	)
	(segment
		(start 104.514396 -272.96364)
		(end 104.499664 -272.955004)
		(width 0.0889)
		(layer "B.Cu")
		(net "FM_CPU1_PKGID0")
	)
	(segment
		(start 107.238546 -270.521938)
		(end 107.23245 -270.525494)
		(width 0.0889)
		(layer "B.Cu")
		(net "FM_CPU1_PKGID0")
	)
	(segment
		(start 107.425998 -270.175482)
		(end 107.425998 -270.19758)
		(width 0.0889)
		(layer "B.Cu")
		(net "FM_CPU1_PKGID0")
	)
	(segment
		(start 55.192168 -261.15772)
		(end 55.192168 -258.482846)
		(width 0.12954)
		(layer "B.Cu")
		(net "FM_CPU1_PKGID0")
	)
	(segment
		(start 107.912408 -269.126208)
		(end 107.912408 -269.246858)
		(width 0.0889)
		(layer "B.Cu")
		(net "FM_CPU1_PKGID0")
	)
	(segment
		(start 93.156278 -273.76882)
		(end 93.141546 -273.777456)
		(width 0.0889)
		(layer "B.Cu")
		(net "FM_CPU1_PKGID0")
	)
	(segment
		(start 42.981118 -193.12001)
		(end 44.6405 -191.460628)
		(width 0.12954)
		(layer "B.Cu")
		(net "FM_CPU1_PKGID0")
	)
	(segment
		(start 102.726744 -273.443192)
		(end 102.726744 -273.461734)
		(width 0.0889)
		(layer "B.Cu")
		(net "FM_CPU1_PKGID0")
	)
	(segment
		(start 96.915478 -273.76882)
		(end 96.900746 -273.777456)
		(width 0.0889)
		(layer "B.Cu")
		(net "FM_CPU1_PKGID0")
	)
	(segment
		(start 59.292998 -262.46201)
		(end 59.120278 -262.28929)
		(width 0.12954)
		(layer "B.Cu")
		(net "FM_CPU1_PKGID0")
	)
	(segment
		(start 86.375748 -273.827494)
		(end 85.249258 -273.827494)
		(width 0.0889)
		(layer "B.Cu")
		(net "FM_CPU1_PKGID0")
	)
	(segment
		(start 97.855278 -273.76882)
		(end 97.840546 -273.777456)
		(width 0.0889)
		(layer "B.Cu")
		(net "FM_CPU1_PKGID0")
	)
	(segment
		(start 99.734878 -273.76882)
		(end 99.720146 -273.777456)
		(width 0.0889)
		(layer "B.Cu")
		(net "FM_CPU1_PKGID0")
	)
	(segment
		(start 107.599226 -268.22273)
		(end 107.599226 -268.813026)
		(width 0.0889)
		(layer "B.Cu")
		(net "FM_CPU1_PKGID0")
	)
	(segment
		(start 70.251828 -264.388346)
		(end 68.053712 -262.19023)
		(width 0.12954)
		(layer "B.Cu")
		(net "FM_CPU1_PKGID0")
	)
	(segment
		(start 84.118196 -273.68881)
		(end 79.552292 -273.68881)
		(width 0.12954)
		(layer "B.Cu")
		(net "FM_CPU1_PKGID0")
	)
	(segment
		(start 62.968124 -262.19023)
		(end 62.696344 -262.46201)
		(width 0.12954)
		(layer "B.Cu")
		(net "FM_CPU1_PKGID0")
	)
	(segment
		(start 55.192168 -258.482846)
		(end 53.331872 -256.62255)
		(width 0.12954)
		(layer "B.Cu")
		(net "FM_CPU1_PKGID0")
	)
	(segment
		(start 107.599226 -268.813026)
		(end 107.912408 -269.126208)
		(width 0.0889)
		(layer "B.Cu")
		(net "FM_CPU1_PKGID0")
	)
	(segment
		(start 106.307636 -272.14449)
		(end 106.298746 -272.14957)
		(width 0.0889)
		(layer "B.Cu")
		(net "FM_CPU1_PKGID0")
	)
	(segment
		(start 62.696344 -262.46201)
		(end 59.292998 -262.46201)
		(width 0.12954)
		(layer "B.Cu")
		(net "FM_CPU1_PKGID0")
	)
	(segment
		(start 44.6405 -191.460628)
		(end 50.3809 -191.460628)
		(width 0.12954)
		(layer "B.Cu")
		(net "FM_CPU1_PKGID0")
	)
	(segment
		(start 95.975678 -273.76882)
		(end 95.960946 -273.777456)
		(width 0.0889)
		(layer "B.Cu")
		(net "FM_CPU1_PKGID0")
	)
	(segment
		(start 53.331872 -256.62255)
		(end 47.189644 -256.62255)
		(width 0.12954)
		(layer "B.Cu")
		(net "FM_CPU1_PKGID0")
	)
	(segment
		(start 79.552292 -273.68881)
		(end 70.251828 -264.388346)
		(width 0.12954)
		(layer "B.Cu")
		(net "FM_CPU1_PKGID0")
	)
	(segment
		(start 42.981118 -252.414024)
		(end 42.981118 -193.12001)
		(width 0.12954)
		(layer "B.Cu")
		(net "FM_CPU1_PKGID0")
	)
	(segment
		(start 106.777282 -271.330674)
		(end 106.768392 -271.335754)
		(width 0.0889)
		(layer "B.Cu")
		(net "FM_CPU1_PKGID0")
	)
	(segment
		(start 92.216478 -273.76882)
		(end 92.201746 -273.777456)
		(width 0.0889)
		(layer "B.Cu")
		(net "FM_CPU1_PKGID0")
	)
	(segment
		(start 107.247436 -270.516858)
		(end 107.238546 -270.521938)
		(width 0.0889)
		(layer "B.Cu")
		(net "FM_CPU1_PKGID0")
	)
	(segment
		(start 106.486198 -271.809718)
		(end 106.486198 -271.825212)
		(width 0.0889)
		(layer "B.Cu")
		(net "FM_CPU1_PKGID0")
	)
	(segment
		(start 98.795078 -273.76882)
		(end 98.780346 -273.777456)
		(width 0.0889)
		(layer "B.Cu")
		(net "FM_CPU1_PKGID0")
	)
	(segment
		(start 86.57336 -273.77136)
		(end 86.562946 -273.777456)
		(width 0.0889)
		(layer "B.Cu")
		(net "FM_CPU1_PKGID0")
	)
	(segment
		(start 68.053712 -262.19023)
		(end 62.968124 -262.19023)
		(width 0.12954)
		(layer "B.Cu")
		(net "FM_CPU1_PKGID0")
	)
	(segment
		(start 101.609906 -273.77136)
		(end 101.599492 -273.777456)
		(width 0.0889)
		(layer "B.Cu")
		(net "FM_CPU1_PKGID0")
	)
	(segment
		(start 90.332306 -273.77136)
		(end 90.321892 -273.777456)
		(width 0.0889)
		(layer "B.Cu")
		(net "FM_CPU1_PKGID0")
	)
	(segment
		(start 105.837482 -272.95856)
		(end 105.828592 -272.96364)
		(width 0.0889)
		(layer "B.Cu")
		(net "FM_CPU1_PKGID0")
	)
	(segment
		(start 52.61356 -189.227968)
		(end 52.61356 -187.569348)
		(width 0.12954)
		(layer "B.Cu")
		(net "FM_CPU1_PKGID0")
	)
	(segment
		(start 108.066078 -267.755878)
		(end 107.599226 -268.22273)
		(width 0.0889)
		(layer "B.Cu")
		(net "FM_CPU1_PKGID0")
	)
	(segment
		(start 56.323738 -262.28929)
		(end 55.192168 -261.15772)
		(width 0.12954)
		(layer "B.Cu")
		(net "FM_CPU1_PKGID0")
	)
	(segment
		(start 105.454196 -272.96364)
		(end 105.439464 -272.955004)
		(width 0.0889)
		(layer "B.Cu")
		(net "FM_CPU1_PKGID0")
	)
	(segment
		(start 47.189644 -256.62255)
		(end 42.981118 -252.414024)
		(width 0.12954)
		(layer "B.Cu")
		(net "FM_CPU1_PKGID0")
	)
	(segment
		(start 50.3809 -191.460628)
		(end 52.61356 -189.227968)
		(width 0.12954)
		(layer "B.Cu")
		(net "FM_CPU1_PKGID0")
	)
	(segment
		(start 85.110574 -273.68881)
		(end 84.118196 -273.68881)
		(width 0.0889)
		(layer "B.Cu")
		(net "FM_CPU1_PKGID0")
	)
	(segment
		(start 107.717082 -269.702788)
		(end 107.708192 -269.707868)
		(width 0.0889)
		(layer "B.Cu")
		(net "FM_CPU1_PKGID0")
	)
	(segment
		(start 108.460794 -267.755878)
		(end 108.066078 -267.755878)
		(width 0.0889)
		(layer "B.Cu")
		(net "FM_CPU1_PKGID0")
	)
	(segment
		(start 100.67036 -273.77136)
		(end 100.659946 -273.777456)
		(width 0.0889)
		(layer "B.Cu")
		(net "FM_CPU1_PKGID0")
	)
	(segment
		(start 95.031306 -273.77136)
		(end 95.020892 -273.777456)
		(width 0.0889)
		(layer "B.Cu")
		(net "FM_CPU1_PKGID0")
	)
	(segment
		(start 106.016044 -272.625058)
		(end 106.016044 -272.639282)
		(width 0.0889)
		(layer "B.Cu")
		(net "FM_CPU1_PKGID0")
	)
	(segment
		(start 85.249258 -273.827494)
		(end 85.110574 -273.68881)
		(width 0.0889)
		(layer "B.Cu")
		(net "FM_CPU1_PKGID0")
	)
	(segment
		(start 94.09176 -273.77136)
		(end 94.081346 -273.777456)
		(width 0.0889)
		(layer "B.Cu")
		(net "FM_CPU1_PKGID0")
	)
	(segment
		(start 59.120278 -262.28929)
		(end 56.323738 -262.28929)
		(width 0.12954)
		(layer "B.Cu")
		(net "FM_CPU1_PKGID0")
	)
	(arc
		(start 100.28555 -273.777456)
		(mid 100.011351 -273.701621)
		(end 99.734878 -273.76882)
		(width 0.0889)
		(layer "B.Cu")
		(net "FM_CPU1_PKGID0")
	)
	(arc
		(start 103.009192 -272.96364)
		(mid 102.804857 -273.166245)
		(end 102.726744 -273.443192)
		(width 0.0889)
		(layer "B.Cu")
		(net "FM_CPU1_PKGID0")
	)
	(arc
		(start 103.948992 -272.96364)
		(mid 103.761794 -273.013783)
		(end 103.574596 -272.96364)
		(width 0.0889)
		(layer "B.Cu")
		(net "FM_CPU1_PKGID0")
	)
	(arc
		(start 102.726744 -273.461734)
		(mid 102.674474 -273.644099)
		(end 102.539546 -273.777456)
		(width 0.0889)
		(layer "B.Cu")
		(net "FM_CPU1_PKGID0")
	)
	(arc
		(start 89.007696 -273.777456)
		(mid 88.724994 -273.70168)
		(end 88.442292 -273.777456)
		(width 0.0889)
		(layer "B.Cu")
		(net "FM_CPU1_PKGID0")
	)
	(arc
		(start 99.34575 -273.777456)
		(mid 99.071551 -273.701621)
		(end 98.795078 -273.76882)
		(width 0.0889)
		(layer "B.Cu")
		(net "FM_CPU1_PKGID0")
	)
	(arc
		(start 93.141546 -273.777456)
		(mid 92.954348 -273.827599)
		(end 92.76715 -273.777456)
		(width 0.0889)
		(layer "B.Cu")
		(net "FM_CPU1_PKGID0")
	)
	(arc
		(start 88.067896 -273.777456)
		(mid 87.785194 -273.70168)
		(end 87.502492 -273.777456)
		(width 0.0889)
		(layer "B.Cu")
		(net "FM_CPU1_PKGID0")
	)
	(arc
		(start 102.539546 -273.777456)
		(mid 102.352348 -273.827599)
		(end 102.16515 -273.777456)
		(width 0.0889)
		(layer "B.Cu")
		(net "FM_CPU1_PKGID0")
	)
	(arc
		(start 91.261946 -273.777456)
		(mid 91.074748 -273.827599)
		(end 90.88755 -273.777456)
		(width 0.0889)
		(layer "B.Cu")
		(net "FM_CPU1_PKGID0")
	)
	(arc
		(start 86.562946 -273.777456)
		(mid 86.472639 -273.814785)
		(end 86.375748 -273.827494)
		(width 0.0889)
		(layer "B.Cu")
		(net "FM_CPU1_PKGID0")
	)
	(arc
		(start 92.201746 -273.777456)
		(mid 92.014548 -273.827599)
		(end 91.82735 -273.777456)
		(width 0.0889)
		(layer "B.Cu")
		(net "FM_CPU1_PKGID0")
	)
	(arc
		(start 92.76715 -273.777456)
		(mid 92.492951 -273.701621)
		(end 92.216478 -273.76882)
		(width 0.0889)
		(layer "B.Cu")
		(net "FM_CPU1_PKGID0")
	)
	(arc
		(start 103.574596 -272.96364)
		(mid 103.291894 -272.887864)
		(end 103.009192 -272.96364)
		(width 0.0889)
		(layer "B.Cu")
		(net "FM_CPU1_PKGID0")
	)
	(arc
		(start 90.88755 -273.777456)
		(mid 90.610737 -273.701586)
		(end 90.332306 -273.77136)
		(width 0.0889)
		(layer "B.Cu")
		(net "FM_CPU1_PKGID0")
	)
	(arc
		(start 104.499664 -272.955004)
		(mid 104.223189 -272.887684)
		(end 103.948992 -272.96364)
		(width 0.0889)
		(layer "B.Cu")
		(net "FM_CPU1_PKGID0")
	)
	(arc
		(start 102.16515 -273.777456)
		(mid 101.888337 -273.701586)
		(end 101.609906 -273.77136)
		(width 0.0889)
		(layer "B.Cu")
		(net "FM_CPU1_PKGID0")
	)
	(arc
		(start 99.720146 -273.777456)
		(mid 99.532948 -273.827599)
		(end 99.34575 -273.777456)
		(width 0.0889)
		(layer "B.Cu")
		(net "FM_CPU1_PKGID0")
	)
	(arc
		(start 106.298746 -272.14957)
		(mid 106.095265 -272.350374)
		(end 106.016044 -272.625058)
		(width 0.0889)
		(layer "B.Cu")
		(net "FM_CPU1_PKGID0")
	)
	(arc
		(start 87.502492 -273.777456)
		(mid 87.315294 -273.827599)
		(end 87.128096 -273.777456)
		(width 0.0889)
		(layer "B.Cu")
		(net "FM_CPU1_PKGID0")
	)
	(arc
		(start 107.912408 -269.246858)
		(mid 107.899852 -269.314672)
		(end 107.895644 -269.38351)
		(width 0.0889)
		(layer "B.Cu")
		(net "FM_CPU1_PKGID0")
	)
	(arc
		(start 97.840546 -273.777456)
		(mid 97.653348 -273.827599)
		(end 97.46615 -273.777456)
		(width 0.0889)
		(layer "B.Cu")
		(net "FM_CPU1_PKGID0")
	)
	(arc
		(start 107.895644 -269.38351)
		(mid 107.847965 -269.56641)
		(end 107.717082 -269.702788)
		(width 0.0889)
		(layer "B.Cu")
		(net "FM_CPU1_PKGID0")
	)
	(arc
		(start 106.016044 -272.639282)
		(mid 105.968365 -272.822182)
		(end 105.837482 -272.95856)
		(width 0.0889)
		(layer "B.Cu")
		(net "FM_CPU1_PKGID0")
	)
	(arc
		(start 87.128096 -273.777456)
		(mid 86.851537 -273.701713)
		(end 86.57336 -273.77136)
		(width 0.0889)
		(layer "B.Cu")
		(net "FM_CPU1_PKGID0")
	)
	(arc
		(start 100.659946 -273.777456)
		(mid 100.472748 -273.827599)
		(end 100.28555 -273.777456)
		(width 0.0889)
		(layer "B.Cu")
		(net "FM_CPU1_PKGID0")
	)
	(arc
		(start 98.780346 -273.777456)
		(mid 98.593148 -273.827599)
		(end 98.40595 -273.777456)
		(width 0.0889)
		(layer "B.Cu")
		(net "FM_CPU1_PKGID0")
	)
	(arc
		(start 97.46615 -273.777456)
		(mid 97.191951 -273.701621)
		(end 96.915478 -273.76882)
		(width 0.0889)
		(layer "B.Cu")
		(net "FM_CPU1_PKGID0")
	)
	(arc
		(start 94.646496 -273.777456)
		(mid 94.369937 -273.701713)
		(end 94.09176 -273.77136)
		(width 0.0889)
		(layer "B.Cu")
		(net "FM_CPU1_PKGID0")
	)
	(arc
		(start 91.82735 -273.777456)
		(mid 91.544648 -273.70168)
		(end 91.261946 -273.777456)
		(width 0.0889)
		(layer "B.Cu")
		(net "FM_CPU1_PKGID0")
	)
	(arc
		(start 105.439464 -272.955004)
		(mid 105.162989 -272.887684)
		(end 104.888792 -272.96364)
		(width 0.0889)
		(layer "B.Cu")
		(net "FM_CPU1_PKGID0")
	)
	(arc
		(start 104.888792 -272.96364)
		(mid 104.701594 -273.013783)
		(end 104.514396 -272.96364)
		(width 0.0889)
		(layer "B.Cu")
		(net "FM_CPU1_PKGID0")
	)
	(arc
		(start 95.960946 -273.777456)
		(mid 95.773748 -273.827599)
		(end 95.58655 -273.777456)
		(width 0.0889)
		(layer "B.Cu")
		(net "FM_CPU1_PKGID0")
	)
	(arc
		(start 101.599492 -273.777456)
		(mid 101.412294 -273.827599)
		(end 101.225096 -273.777456)
		(width 0.0889)
		(layer "B.Cu")
		(net "FM_CPU1_PKGID0")
	)
	(arc
		(start 94.081346 -273.777456)
		(mid 93.894148 -273.827599)
		(end 93.70695 -273.777456)
		(width 0.0889)
		(layer "B.Cu")
		(net "FM_CPU1_PKGID0")
	)
	(arc
		(start 95.58655 -273.777456)
		(mid 95.309737 -273.701586)
		(end 95.031306 -273.77136)
		(width 0.0889)
		(layer "B.Cu")
		(net "FM_CPU1_PKGID0")
	)
	(arc
		(start 98.40595 -273.777456)
		(mid 98.131751 -273.701621)
		(end 97.855278 -273.76882)
		(width 0.0889)
		(layer "B.Cu")
		(net "FM_CPU1_PKGID0")
	)
	(arc
		(start 88.442292 -273.777456)
		(mid 88.255094 -273.827599)
		(end 88.067896 -273.777456)
		(width 0.0889)
		(layer "B.Cu")
		(net "FM_CPU1_PKGID0")
	)
	(arc
		(start 106.768392 -271.335754)
		(mid 106.565569 -271.535985)
		(end 106.486198 -271.809718)
		(width 0.0889)
		(layer "B.Cu")
		(net "FM_CPU1_PKGID0")
	)
	(arc
		(start 107.425998 -270.19758)
		(mid 107.378319 -270.38048)
		(end 107.247436 -270.516858)
		(width 0.0889)
		(layer "B.Cu")
		(net "FM_CPU1_PKGID0")
	)
	(arc
		(start 101.225096 -273.777456)
		(mid 100.948537 -273.701713)
		(end 100.67036 -273.77136)
		(width 0.0889)
		(layer "B.Cu")
		(net "FM_CPU1_PKGID0")
	)
	(arc
		(start 105.828592 -272.96364)
		(mid 105.641394 -273.013783)
		(end 105.454196 -272.96364)
		(width 0.0889)
		(layer "B.Cu")
		(net "FM_CPU1_PKGID0")
	)
	(arc
		(start 96.900746 -273.777456)
		(mid 96.713548 -273.827599)
		(end 96.52635 -273.777456)
		(width 0.0889)
		(layer "B.Cu")
		(net "FM_CPU1_PKGID0")
	)
	(arc
		(start 93.70695 -273.777456)
		(mid 93.432751 -273.701621)
		(end 93.156278 -273.76882)
		(width 0.0889)
		(layer "B.Cu")
		(net "FM_CPU1_PKGID0")
	)
	(arc
		(start 89.382092 -273.777456)
		(mid 89.194894 -273.827599)
		(end 89.007696 -273.777456)
		(width 0.0889)
		(layer "B.Cu")
		(net "FM_CPU1_PKGID0")
	)
	(arc
		(start 89.947496 -273.777456)
		(mid 89.664794 -273.70168)
		(end 89.382092 -273.777456)
		(width 0.0889)
		(layer "B.Cu")
		(net "FM_CPU1_PKGID0")
	)
	(arc
		(start 90.321892 -273.777456)
		(mid 90.134694 -273.827599)
		(end 89.947496 -273.777456)
		(width 0.0889)
		(layer "B.Cu")
		(net "FM_CPU1_PKGID0")
	)
	(arc
		(start 95.020892 -273.777456)
		(mid 94.833694 -273.827599)
		(end 94.646496 -273.777456)
		(width 0.0889)
		(layer "B.Cu")
		(net "FM_CPU1_PKGID0")
	)
	(arc
		(start 96.52635 -273.777456)
		(mid 96.252151 -273.701621)
		(end 95.975678 -273.76882)
		(width 0.0889)
		(layer "B.Cu")
		(net "FM_CPU1_PKGID0")
	)
	(arc
		(start 107.23245 -270.525494)
		(mid 107.029863 -270.731845)
		(end 106.955844 -271.011396)
		(width 0.0889)
		(layer "B.Cu")
		(net "FM_CPU1_PKGID0")
	)
	(arc
		(start 106.955844 -271.011396)
		(mid 106.908165 -271.194296)
		(end 106.777282 -271.330674)
		(width 0.0889)
		(layer "B.Cu")
		(net "FM_CPU1_PKGID0")
	)
	(arc
		(start 106.486198 -271.825212)
		(mid 106.438519 -272.008112)
		(end 106.307636 -272.14449)
		(width 0.0889)
		(layer "B.Cu")
		(net "FM_CPU1_PKGID0")
	)
	(arc
		(start 107.708192 -269.707868)
		(mid 107.50691 -269.905355)
		(end 107.425998 -270.175482)
		(width 0.0889)
		(layer "B.Cu")
		(net "FM_CPU1_PKGID0")
	)
	(segment
		(start 184.96788 -132.425948)
		(end 184.61228 -132.781548)
		(width 0.127)
		(layer "In4.Cu")
		(net "FM_CPU1_PKGID0")
	)
	(segment
		(start 143.76146 -135.270748)
		(end 129.405634 -149.626574)
		(width 0.127)
		(layer "In4.Cu")
		(net "FM_CPU1_PKGID0")
	)
	(segment
		(start 58.39968 -187.366148)
		(end 58.19648 -187.569348)
		(width 0.127)
		(layer "In4.Cu")
		(net "FM_CPU1_PKGID0")
	)
	(segment
		(start 184.61228 -133.721348)
		(end 184.09158 -134.242048)
		(width 0.127)
		(layer "In4.Cu")
		(net "FM_CPU1_PKGID0")
	)
	(segment
		(start 169.355008 -134.242048)
		(end 166.871396 -135.270748)
		(width 0.127)
		(layer "In4.Cu")
		(net "FM_CPU1_PKGID0")
	)
	(segment
		(start 166.871396 -135.270748)
		(end 143.76146 -135.270748)
		(width 0.127)
		(layer "In4.Cu")
		(net "FM_CPU1_PKGID0")
	)
	(segment
		(start 58.19648 -187.569348)
		(end 52.61356 -187.569348)
		(width 0.127)
		(layer "In4.Cu")
		(net "FM_CPU1_PKGID0")
	)
	(segment
		(start 129.405634 -149.626574)
		(end 110.617254 -149.626574)
		(width 0.127)
		(layer "In4.Cu")
		(net "FM_CPU1_PKGID0")
	)
	(segment
		(start 74.17308 -183.731916)
		(end 70.258432 -183.731916)
		(width 0.127)
		(layer "In4.Cu")
		(net "FM_CPU1_PKGID0")
	)
	(segment
		(start 70.258432 -183.731916)
		(end 69.8246 -184.165748)
		(width 0.127)
		(layer "In4.Cu")
		(net "FM_CPU1_PKGID0")
	)
	(segment
		(start 77.55382 -182.690008)
		(end 77.55382 -183.680608)
		(width 0.127)
		(layer "In4.Cu")
		(net "FM_CPU1_PKGID0")
	)
	(segment
		(start 69.1388 -184.343548)
		(end 69.1388 -185.359548)
		(width 0.127)
		(layer "In4.Cu")
		(net "FM_CPU1_PKGID0")
	)
	(segment
		(start 74.606912 -184.165748)
		(end 74.17308 -183.731916)
		(width 0.127)
		(layer "In4.Cu")
		(net "FM_CPU1_PKGID0")
	)
	(segment
		(start 77.06868 -184.165748)
		(end 74.606912 -184.165748)
		(width 0.127)
		(layer "In4.Cu")
		(net "FM_CPU1_PKGID0")
	)
	(segment
		(start 69.3166 -184.165748)
		(end 69.1388 -184.343548)
		(width 0.127)
		(layer "In4.Cu")
		(net "FM_CPU1_PKGID0")
	)
	(segment
		(start 184.09158 -134.242048)
		(end 169.355008 -134.242048)
		(width 0.127)
		(layer "In4.Cu")
		(net "FM_CPU1_PKGID0")
	)
	(segment
		(start 67.1322 -187.366148)
		(end 58.39968 -187.366148)
		(width 0.127)
		(layer "In4.Cu")
		(net "FM_CPU1_PKGID0")
	)
	(segment
		(start 110.617254 -149.626574)
		(end 77.55382 -182.690008)
		(width 0.127)
		(layer "In4.Cu")
		(net "FM_CPU1_PKGID0")
	)
	(segment
		(start 69.8246 -184.165748)
		(end 69.3166 -184.165748)
		(width 0.127)
		(layer "In4.Cu")
		(net "FM_CPU1_PKGID0")
	)
	(segment
		(start 184.61228 -132.781548)
		(end 184.61228 -133.721348)
		(width 0.127)
		(layer "In4.Cu")
		(net "FM_CPU1_PKGID0")
	)
	(segment
		(start 69.1388 -185.359548)
		(end 67.1322 -187.366148)
		(width 0.127)
		(layer "In4.Cu")
		(net "FM_CPU1_PKGID0")
	)
	(segment
		(start 77.55382 -183.680608)
		(end 77.06868 -184.165748)
		(width 0.127)
		(layer "In4.Cu")
		(net "FM_CPU1_PKGID0")
	)
	(via
		(at 199.010778 -193.51625)
		(size 0.508)
		(drill 0.254)
		(layers "F.Cu" "B.Cu")
		(net "FM_CPU0_SKTOCC_N")
	)
	(via
		(at 205.9559 -195.649088)
		(size 0.508)
		(drill 0.254)
		(layers "F.Cu" "B.Cu")
		(net "FM_CPU0_SKTOCC_N")
	)
	(segment
		(start 205.9559 -194.023996)
		(end 205.9559 -195.649088)
		(width 0.12954)
		(layer "B.Cu")
		(net "FM_CPU0_SKTOCC_N")
	)
	(segment
		(start 201.562208 -192.64757)
		(end 201.323448 -192.40881)
		(width 0.12954)
		(layer "B.Cu")
		(net "FM_CPU0_SKTOCC_N")
	)
	(segment
		(start 199.067928 -193.51625)
		(end 199.010778 -193.51625)
		(width 0.12954)
		(layer "B.Cu")
		(net "FM_CPU0_SKTOCC_N")
	)
	(segment
		(start 198.650098 -193.51625)
		(end 198.401432 -193.267584)
		(width 0.12954)
		(layer "B.Cu")
		(net "FM_CPU0_SKTOCC_N")
	)
	(segment
		(start 199.631808 -192.95237)
		(end 199.067928 -193.51625)
		(width 0.12954)
		(layer "B.Cu")
		(net "FM_CPU0_SKTOCC_N")
	)
	(segment
		(start 200.175368 -192.40881)
		(end 199.631808 -192.95237)
		(width 0.12954)
		(layer "B.Cu")
		(net "FM_CPU0_SKTOCC_N")
	)
	(segment
		(start 199.010778 -193.51625)
		(end 198.650098 -193.51625)
		(width 0.12954)
		(layer "B.Cu")
		(net "FM_CPU0_SKTOCC_N")
	)
	(segment
		(start 201.323448 -192.40881)
		(end 200.175368 -192.40881)
		(width 0.12954)
		(layer "B.Cu")
		(net "FM_CPU0_SKTOCC_N")
	)
	(segment
		(start 198.401432 -193.267584)
		(end 197.795896 -193.267584)
		(width 0.12954)
		(layer "B.Cu")
		(net "FM_CPU0_SKTOCC_N")
	)
	(segment
		(start 202.87488 -194.528948)
		(end 205.572106 -194.528948)
		(width 0.127)
		(layer "In4.Cu")
		(net "FM_CPU0_SKTOCC_N")
	)
	(segment
		(start 205.9559 -194.912742)
		(end 205.9559 -195.649088)
		(width 0.127)
		(layer "In4.Cu")
		(net "FM_CPU0_SKTOCC_N")
	)
	(segment
		(start 202.49388 -194.147948)
		(end 202.87488 -194.528948)
		(width 0.127)
		(layer "In4.Cu")
		(net "FM_CPU0_SKTOCC_N")
	)
	(segment
		(start 199.010778 -193.51625)
		(end 199.642476 -194.147948)
		(width 0.127)
		(layer "In4.Cu")
		(net "FM_CPU0_SKTOCC_N")
	)
	(segment
		(start 205.572106 -194.528948)
		(end 205.9559 -194.912742)
		(width 0.127)
		(layer "In4.Cu")
		(net "FM_CPU0_SKTOCC_N")
	)
	(segment
		(start 199.642476 -194.147948)
		(end 202.49388 -194.147948)
		(width 0.127)
		(layer "In4.Cu")
		(net "FM_CPU0_SKTOCC_N")
	)
	(segment
		(start 178.9557 -116.975382)
		(end 179.35575 -117.375432)
		(width 0.12954)
		(layer "F.Cu")
		(net "FM_CPU0_SKTOCC_LVT3_PLD_N")
	)
	(segment
		(start 176.58588 -129.866898)
		(end 176.58588 -129.250948)
		(width 0.12954)
		(layer "F.Cu")
		(net "FM_CPU0_SKTOCC_LVT3_PLD_N")
	)
	(via
		(at 179.35575 -117.375432)
		(size 0.4572)
		(drill 0.254)
		(layers "F.Cu" "B.Cu")
		(net "FM_CPU0_SKTOCC_LVT3_PLD_N")
	)
	(via
		(at 176.58588 -129.250948)
		(size 0.508)
		(drill 0.254)
		(layers "F.Cu" "B.Cu")
		(net "FM_CPU0_SKTOCC_LVT3_PLD_N")
	)
	(segment
		(start 177.84826 -122.707908)
		(end 178.19116 -122.365008)
		(width 0.127)
		(layer "In2.Cu")
		(net "FM_CPU0_SKTOCC_LVT3_PLD_N")
	)
	(segment
		(start 178.45278 -120.985534)
		(end 178.45278 -118.278402)
		(width 0.127)
		(layer "In2.Cu")
		(net "FM_CPU0_SKTOCC_LVT3_PLD_N")
	)
	(segment
		(start 177.52822 -128.98628)
		(end 177.52822 -123.792488)
		(width 0.127)
		(layer "In2.Cu")
		(net "FM_CPU0_SKTOCC_LVT3_PLD_N")
	)
	(segment
		(start 177.84826 -123.472448)
		(end 177.84826 -122.707908)
		(width 0.127)
		(layer "In2.Cu")
		(net "FM_CPU0_SKTOCC_LVT3_PLD_N")
	)
	(segment
		(start 177.263552 -129.250948)
		(end 177.52822 -128.98628)
		(width 0.127)
		(layer "In2.Cu")
		(net "FM_CPU0_SKTOCC_LVT3_PLD_N")
	)
	(segment
		(start 178.45278 -118.278402)
		(end 179.35575 -117.375432)
		(width 0.127)
		(layer "In2.Cu")
		(net "FM_CPU0_SKTOCC_LVT3_PLD_N")
	)
	(segment
		(start 178.19116 -121.247154)
		(end 178.45278 -120.985534)
		(width 0.127)
		(layer "In2.Cu")
		(net "FM_CPU0_SKTOCC_LVT3_PLD_N")
	)
	(segment
		(start 176.58588 -129.250948)
		(end 177.263552 -129.250948)
		(width 0.127)
		(layer "In2.Cu")
		(net "FM_CPU0_SKTOCC_LVT3_PLD_N")
	)
	(segment
		(start 178.19116 -122.365008)
		(end 178.19116 -121.247154)
		(width 0.127)
		(layer "In2.Cu")
		(net "FM_CPU0_SKTOCC_LVT3_PLD_N")
	)
	(segment
		(start 177.52822 -123.792488)
		(end 177.84826 -123.472448)
		(width 0.127)
		(layer "In2.Cu")
		(net "FM_CPU0_SKTOCC_LVT3_PLD_N")
	)
	(segment
		(start 176.58588 -130.666998)
		(end 176.58588 -131.280408)
		(width 0.12954)
		(layer "F.Cu")
		(net "FM_CPU0_SKTOCC_LVT3_N")
	)
	(segment
		(start 363.919516 -268.84757)
		(end 363.919516 -269.383256)
		(width 0.12954)
		(layer "F.Cu")
		(net "FM_CPU0_SKTOCC_LVT3_N")
	)
	(segment
		(start 363.919516 -269.383256)
		(end 363.919262 -269.38351)
		(width 0.12954)
		(layer "F.Cu")
		(net "FM_CPU0_SKTOCC_LVT3_N")
	)
	(via
		(at 403.468586 -271.49933)
		(size 0.6604)
		(drill 0.3302)
		(layers "F.Cu" "B.Cu")
		(net "FM_CPU0_SKTOCC_LVT3_N")
	)
	(via
		(at 176.58588 -131.280408)
		(size 0.508)
		(drill 0.254)
		(layers "F.Cu" "B.Cu")
		(net "FM_CPU0_SKTOCC_LVT3_N")
	)
	(via
		(at 425.16044 -184.536588)
		(size 0.508)
		(drill 0.254)
		(layers "F.Cu" "B.Cu")
		(net "FM_CPU0_SKTOCC_LVT3_N")
	)
	(via
		(at 195.38188 -134.711948)
		(size 0.508)
		(drill 0.254)
		(layers "F.Cu" "B.Cu")
		(net "FM_CPU0_SKTOCC_LVT3_N")
	)
	(via
		(at 202.362308 -193.34353)
		(size 0.508)
		(drill 0.254)
		(layers "F.Cu" "B.Cu")
		(net "FM_CPU0_SKTOCC_LVT3_N")
	)
	(via
		(at 363.919262 -269.38351)
		(size 0.4572)
		(drill 0.2032)
		(layers "F.Cu" "B.Cu")
		(net "FM_CPU0_SKTOCC_LVT3_N")
	)
	(segment
		(start 386.79628 -270.330168)
		(end 384.38328 -270.330168)
		(width 0.12954)
		(layer "B.Cu")
		(net "FM_CPU0_SKTOCC_LVT3_N")
	)
	(segment
		(start 416.36188 -258.06781)
		(end 416.36188 -272.27403)
		(width 0.12954)
		(layer "B.Cu")
		(net "FM_CPU0_SKTOCC_LVT3_N")
	)
	(segment
		(start 418.13988 -256.28981)
		(end 416.36188 -258.06781)
		(width 0.12954)
		(layer "B.Cu")
		(net "FM_CPU0_SKTOCC_LVT3_N")
	)
	(segment
		(start 416.36188 -272.27403)
		(end 415.87928 -272.75663)
		(width 0.12954)
		(layer "B.Cu")
		(net "FM_CPU0_SKTOCC_LVT3_N")
	)
	(segment
		(start 364.233206 -269.38351)
		(end 363.919262 -269.38351)
		(width 0.12954)
		(layer "B.Cu")
		(net "FM_CPU0_SKTOCC_LVT3_N")
	)
	(segment
		(start 415.87928 -272.75663)
		(end 412.950406 -272.75663)
		(width 0.12954)
		(layer "B.Cu")
		(net "FM_CPU0_SKTOCC_LVT3_N")
	)
	(segment
		(start 387.105398 -270.02105)
		(end 386.79628 -270.330168)
		(width 0.12954)
		(layer "B.Cu")
		(net "FM_CPU0_SKTOCC_LVT3_N")
	)
	(segment
		(start 405.462486 -272.96745)
		(end 403.994366 -271.49933)
		(width 0.12954)
		(layer "B.Cu")
		(net "FM_CPU0_SKTOCC_LVT3_N")
	)
	(segment
		(start 388.195566 -270.25981)
		(end 387.956806 -270.02105)
		(width 0.12954)
		(layer "B.Cu")
		(net "FM_CPU0_SKTOCC_LVT3_N")
	)
	(segment
		(start 403.468586 -271.49933)
		(end 401.192746 -271.49933)
		(width 0.12954)
		(layer "B.Cu")
		(net "FM_CPU0_SKTOCC_LVT3_N")
	)
	(segment
		(start 399.953226 -270.25981)
		(end 388.195566 -270.25981)
		(width 0.12954)
		(layer "B.Cu")
		(net "FM_CPU0_SKTOCC_LVT3_N")
	)
	(segment
		(start 403.994366 -271.49933)
		(end 403.468586 -271.49933)
		(width 0.12954)
		(layer "B.Cu")
		(net "FM_CPU0_SKTOCC_LVT3_N")
	)
	(segment
		(start 364.644686 -269.79499)
		(end 364.233206 -269.38351)
		(width 0.12954)
		(layer "B.Cu")
		(net "FM_CPU0_SKTOCC_LVT3_N")
	)
	(segment
		(start 412.950406 -272.75663)
		(end 412.599886 -272.40611)
		(width 0.12954)
		(layer "B.Cu")
		(net "FM_CPU0_SKTOCC_LVT3_N")
	)
	(segment
		(start 383.848102 -269.79499)
		(end 364.644686 -269.79499)
		(width 0.12954)
		(layer "B.Cu")
		(net "FM_CPU0_SKTOCC_LVT3_N")
	)
	(segment
		(start 401.192746 -271.49933)
		(end 399.953226 -270.25981)
		(width 0.12954)
		(layer "B.Cu")
		(net "FM_CPU0_SKTOCC_LVT3_N")
	)
	(segment
		(start 412.599886 -272.40611)
		(end 409.066746 -272.40611)
		(width 0.12954)
		(layer "B.Cu")
		(net "FM_CPU0_SKTOCC_LVT3_N")
	)
	(segment
		(start 408.505406 -272.96745)
		(end 405.462486 -272.96745)
		(width 0.12954)
		(layer "B.Cu")
		(net "FM_CPU0_SKTOCC_LVT3_N")
	)
	(segment
		(start 418.87648 -244.592348)
		(end 418.13988 -245.328948)
		(width 0.12954)
		(layer "B.Cu")
		(net "FM_CPU0_SKTOCC_LVT3_N")
	)
	(segment
		(start 387.956806 -270.02105)
		(end 387.105398 -270.02105)
		(width 0.12954)
		(layer "B.Cu")
		(net "FM_CPU0_SKTOCC_LVT3_N")
	)
	(segment
		(start 425.16044 -184.536588)
		(end 418.87648 -190.820548)
		(width 0.12954)
		(layer "B.Cu")
		(net "FM_CPU0_SKTOCC_LVT3_N")
	)
	(segment
		(start 418.87648 -190.820548)
		(end 418.87648 -244.592348)
		(width 0.12954)
		(layer "B.Cu")
		(net "FM_CPU0_SKTOCC_LVT3_N")
	)
	(segment
		(start 409.066746 -272.40611)
		(end 408.505406 -272.96745)
		(width 0.12954)
		(layer "B.Cu")
		(net "FM_CPU0_SKTOCC_LVT3_N")
	)
	(segment
		(start 384.38328 -270.330168)
		(end 383.848102 -269.79499)
		(width 0.12954)
		(layer "B.Cu")
		(net "FM_CPU0_SKTOCC_LVT3_N")
	)
	(segment
		(start 418.13988 -245.328948)
		(end 418.13988 -256.28981)
		(width 0.12954)
		(layer "B.Cu")
		(net "FM_CPU0_SKTOCC_LVT3_N")
	)
	(segment
		(start 202.362308 -192.64757)
		(end 202.362308 -193.34353)
		(width 0.12954)
		(layer "B.Cu")
		(net "FM_CPU0_SKTOCC_LVT3_N")
	)
	(segment
		(start 209.414618 -148.541486)
		(end 197.129146 -136.256014)
		(width 0.127)
		(layer "In2.Cu")
		(net "FM_CPU0_SKTOCC_LVT3_N")
	)
	(segment
		(start 210.24088 -164.342826)
		(end 210.24088 -150.536402)
		(width 0.127)
		(layer "In2.Cu")
		(net "FM_CPU0_SKTOCC_LVT3_N")
	)
	(segment
		(start 209.975958 -164.607748)
		(end 210.24088 -164.342826)
		(width 0.127)
		(layer "In2.Cu")
		(net "FM_CPU0_SKTOCC_LVT3_N")
	)
	(segment
		(start 202.362308 -193.34353)
		(end 202.362308 -192.424304)
		(width 0.127)
		(layer "In2.Cu")
		(net "FM_CPU0_SKTOCC_LVT3_N")
	)
	(segment
		(start 203.686918 -189.22619)
		(end 203.686918 -188.25337)
		(width 0.127)
		(layer "In2.Cu")
		(net "FM_CPU0_SKTOCC_LVT3_N")
	)
	(segment
		(start 202.362308 -192.424304)
		(end 203.686918 -189.22619)
		(width 0.127)
		(layer "In2.Cu")
		(net "FM_CPU0_SKTOCC_LVT3_N")
	)
	(segment
		(start 196.11848 -136.256014)
		(end 195.38188 -135.519414)
		(width 0.127)
		(layer "In2.Cu")
		(net "FM_CPU0_SKTOCC_LVT3_N")
	)
	(segment
		(start 209.975958 -181.96433)
		(end 209.975958 -164.607748)
		(width 0.127)
		(layer "In2.Cu")
		(net "FM_CPU0_SKTOCC_LVT3_N")
	)
	(segment
		(start 195.38188 -135.519414)
		(end 195.38188 -134.711948)
		(width 0.127)
		(layer "In2.Cu")
		(net "FM_CPU0_SKTOCC_LVT3_N")
	)
	(segment
		(start 203.686918 -188.25337)
		(end 209.975958 -181.96433)
		(width 0.127)
		(layer "In2.Cu")
		(net "FM_CPU0_SKTOCC_LVT3_N")
	)
	(segment
		(start 197.129146 -136.256014)
		(end 196.11848 -136.256014)
		(width 0.127)
		(layer "In2.Cu")
		(net "FM_CPU0_SKTOCC_LVT3_N")
	)
	(segment
		(start 210.24088 -150.536402)
		(end 209.414618 -148.541486)
		(width 0.127)
		(layer "In2.Cu")
		(net "FM_CPU0_SKTOCC_LVT3_N")
	)
	(segment
		(start 251.69114 -125.174248)
		(end 248.75744 -128.107948)
		(width 0.127)
		(layer "In15.Cu")
		(net "FM_CPU0_SKTOCC_LVT3_N")
	)
	(segment
		(start 190.462154 -133.157468)
		(end 188.583824 -131.279138)
		(width 0.127)
		(layer "In15.Cu")
		(net "FM_CPU0_SKTOCC_LVT3_N")
	)
	(segment
		(start 242.33124 -128.107948)
		(end 241.32286 -127.099568)
		(width 0.127)
		(layer "In15.Cu")
		(net "FM_CPU0_SKTOCC_LVT3_N")
	)
	(segment
		(start 224.1042 -129.9718)
		(end 223.82226 -130.25374)
		(width 0.127)
		(layer "In15.Cu")
		(net "FM_CPU0_SKTOCC_LVT3_N")
	)
	(segment
		(start 240.0808 -127.099568)
		(end 236.446568 -130.7338)
		(width 0.127)
		(layer "In15.Cu")
		(net "FM_CPU0_SKTOCC_LVT3_N")
	)
	(segment
		(start 223.82226 -130.25374)
		(end 220.72346 -130.25374)
		(width 0.127)
		(layer "In15.Cu")
		(net "FM_CPU0_SKTOCC_LVT3_N")
	)
	(segment
		(start 425.16044 -181.193948)
		(end 425.567602 -180.786786)
		(width 0.127)
		(layer "In15.Cu")
		(net "FM_CPU0_SKTOCC_LVT3_N")
	)
	(segment
		(start 428.20971 -132.640578)
		(end 427.15688 -131.587748)
		(width 0.127)
		(layer "In15.Cu")
		(net "FM_CPU0_SKTOCC_LVT3_N")
	)
	(segment
		(start 220.72346 -130.25374)
		(end 219.5703 -131.4069)
		(width 0.127)
		(layer "In15.Cu")
		(net "FM_CPU0_SKTOCC_LVT3_N")
	)
	(segment
		(start 185.695336 -131.553458)
		(end 185.457338 -131.791456)
		(width 0.127)
		(layer "In15.Cu")
		(net "FM_CPU0_SKTOCC_LVT3_N")
	)
	(segment
		(start 194.637152 -132.972556)
		(end 191.414146 -132.972556)
		(width 0.127)
		(layer "In15.Cu")
		(net "FM_CPU0_SKTOCC_LVT3_N")
	)
	(segment
		(start 187.36437 -129.892044)
		(end 186.176666 -129.892044)
		(width 0.127)
		(layer "In15.Cu")
		(net "FM_CPU0_SKTOCC_LVT3_N")
	)
	(segment
		(start 409.9687 -125.174248)
		(end 251.69114 -125.174248)
		(width 0.127)
		(layer "In15.Cu")
		(net "FM_CPU0_SKTOCC_LVT3_N")
	)
	(segment
		(start 436.1942 -159.982408)
		(end 436.1942 -154.092148)
		(width 0.127)
		(layer "In15.Cu")
		(net "FM_CPU0_SKTOCC_LVT3_N")
	)
	(segment
		(start 436.1942 -154.092148)
		(end 431.01768 -148.915628)
		(width 0.127)
		(layer "In15.Cu")
		(net "FM_CPU0_SKTOCC_LVT3_N")
	)
	(segment
		(start 191.414146 -132.972556)
		(end 191.229234 -133.157468)
		(width 0.127)
		(layer "In15.Cu")
		(net "FM_CPU0_SKTOCC_LVT3_N")
	)
	(segment
		(start 184.773316 -131.791456)
		(end 184.366408 -132.198364)
		(width 0.127)
		(layer "In15.Cu")
		(net "FM_CPU0_SKTOCC_LVT3_N")
	)
	(segment
		(start 186.176666 -129.892044)
		(end 185.695336 -130.373374)
		(width 0.127)
		(layer "In15.Cu")
		(net "FM_CPU0_SKTOCC_LVT3_N")
	)
	(segment
		(start 212.573108 -131.4069)
		(end 212.415374 -131.564634)
		(width 0.127)
		(layer "In15.Cu")
		(net "FM_CPU0_SKTOCC_LVT3_N")
	)
	(segment
		(start 241.32286 -127.099568)
		(end 240.0808 -127.099568)
		(width 0.127)
		(layer "In15.Cu")
		(net "FM_CPU0_SKTOCC_LVT3_N")
	)
	(segment
		(start 431.01768 -133.541008)
		(end 430.11725 -132.640578)
		(width 0.127)
		(layer "In15.Cu")
		(net "FM_CPU0_SKTOCC_LVT3_N")
	)
	(segment
		(start 437.30672 -169.182288)
		(end 437.30672 -161.094928)
		(width 0.127)
		(layer "In15.Cu")
		(net "FM_CPU0_SKTOCC_LVT3_N")
	)
	(segment
		(start 437.30672 -161.094928)
		(end 436.1942 -159.982408)
		(width 0.127)
		(layer "In15.Cu")
		(net "FM_CPU0_SKTOCC_LVT3_N")
	)
	(segment
		(start 231.180132 -130.7338)
		(end 229.29342 -128.847088)
		(width 0.127)
		(layer "In15.Cu")
		(net "FM_CPU0_SKTOCC_LVT3_N")
	)
	(segment
		(start 177.383694 -133.171692)
		(end 177.15865 -132.946648)
		(width 0.127)
		(layer "In15.Cu")
		(net "FM_CPU0_SKTOCC_LVT3_N")
	)
	(segment
		(start 427.15688 -131.587748)
		(end 422.300908 -131.587748)
		(width 0.127)
		(layer "In15.Cu")
		(net "FM_CPU0_SKTOCC_LVT3_N")
	)
	(segment
		(start 227.195888 -129.9718)
		(end 224.1042 -129.9718)
		(width 0.127)
		(layer "In15.Cu")
		(net "FM_CPU0_SKTOCC_LVT3_N")
	)
	(segment
		(start 210.827366 -131.564634)
		(end 209.00136 -133.39064)
		(width 0.127)
		(layer "In15.Cu")
		(net "FM_CPU0_SKTOCC_LVT3_N")
	)
	(segment
		(start 219.5703 -131.4069)
		(end 212.573108 -131.4069)
		(width 0.127)
		(layer "In15.Cu")
		(net "FM_CPU0_SKTOCC_LVT3_N")
	)
	(segment
		(start 432.639216 -176.219612)
		(end 432.895248 -175.96358)
		(width 0.127)
		(layer "In15.Cu")
		(net "FM_CPU0_SKTOCC_LVT3_N")
	)
	(segment
		(start 177.15865 -132.946648)
		(end 177.15865 -131.853178)
		(width 0.127)
		(layer "In15.Cu")
		(net "FM_CPU0_SKTOCC_LVT3_N")
	)
	(segment
		(start 184.366408 -132.198364)
		(end 184.366408 -132.579364)
		(width 0.127)
		(layer "In15.Cu")
		(net "FM_CPU0_SKTOCC_LVT3_N")
	)
	(segment
		(start 183.994044 -132.951728)
		(end 181.656736 -132.951728)
		(width 0.127)
		(layer "In15.Cu")
		(net "FM_CPU0_SKTOCC_LVT3_N")
	)
	(segment
		(start 212.415374 -131.564634)
		(end 210.827366 -131.564634)
		(width 0.127)
		(layer "In15.Cu")
		(net "FM_CPU0_SKTOCC_LVT3_N")
	)
	(segment
		(start 188.583824 -131.279138)
		(end 188.583824 -131.111498)
		(width 0.127)
		(layer "In15.Cu")
		(net "FM_CPU0_SKTOCC_LVT3_N")
	)
	(segment
		(start 248.75744 -128.107948)
		(end 242.33124 -128.107948)
		(width 0.127)
		(layer "In15.Cu")
		(net "FM_CPU0_SKTOCC_LVT3_N")
	)
	(segment
		(start 425.16044 -184.536588)
		(end 425.16044 -181.193948)
		(width 0.127)
		(layer "In15.Cu")
		(net "FM_CPU0_SKTOCC_LVT3_N")
	)
	(segment
		(start 432.639216 -179.521612)
		(end 432.639216 -176.219612)
		(width 0.127)
		(layer "In15.Cu")
		(net "FM_CPU0_SKTOCC_LVT3_N")
	)
	(segment
		(start 236.446568 -130.7338)
		(end 231.180132 -130.7338)
		(width 0.127)
		(layer "In15.Cu")
		(net "FM_CPU0_SKTOCC_LVT3_N")
	)
	(segment
		(start 431.01768 -148.915628)
		(end 431.01768 -133.541008)
		(width 0.127)
		(layer "In15.Cu")
		(net "FM_CPU0_SKTOCC_LVT3_N")
	)
	(segment
		(start 207.279748 -133.39064)
		(end 205.28534 -135.385048)
		(width 0.127)
		(layer "In15.Cu")
		(net "FM_CPU0_SKTOCC_LVT3_N")
	)
	(segment
		(start 185.695336 -130.373374)
		(end 185.695336 -131.553458)
		(width 0.127)
		(layer "In15.Cu")
		(net "FM_CPU0_SKTOCC_LVT3_N")
	)
	(segment
		(start 228.3206 -128.847088)
		(end 227.195888 -129.9718)
		(width 0.127)
		(layer "In15.Cu")
		(net "FM_CPU0_SKTOCC_LVT3_N")
	)
	(segment
		(start 196.05498 -135.385048)
		(end 195.38188 -134.711948)
		(width 0.127)
		(layer "In15.Cu")
		(net "FM_CPU0_SKTOCC_LVT3_N")
	)
	(segment
		(start 432.895248 -175.96358)
		(end 432.895248 -173.59376)
		(width 0.127)
		(layer "In15.Cu")
		(net "FM_CPU0_SKTOCC_LVT3_N")
	)
	(segment
		(start 185.457338 -131.791456)
		(end 184.773316 -131.791456)
		(width 0.127)
		(layer "In15.Cu")
		(net "FM_CPU0_SKTOCC_LVT3_N")
	)
	(segment
		(start 181.436772 -133.171692)
		(end 177.383694 -133.171692)
		(width 0.127)
		(layer "In15.Cu")
		(net "FM_CPU0_SKTOCC_LVT3_N")
	)
	(segment
		(start 431.374042 -180.786786)
		(end 432.639216 -179.521612)
		(width 0.127)
		(layer "In15.Cu")
		(net "FM_CPU0_SKTOCC_LVT3_N")
	)
	(segment
		(start 195.38188 -134.711948)
		(end 195.38188 -133.717284)
		(width 0.127)
		(layer "In15.Cu")
		(net "FM_CPU0_SKTOCC_LVT3_N")
	)
	(segment
		(start 195.38188 -133.717284)
		(end 194.637152 -132.972556)
		(width 0.127)
		(layer "In15.Cu")
		(net "FM_CPU0_SKTOCC_LVT3_N")
	)
	(segment
		(start 229.29342 -128.847088)
		(end 228.3206 -128.847088)
		(width 0.127)
		(layer "In15.Cu")
		(net "FM_CPU0_SKTOCC_LVT3_N")
	)
	(segment
		(start 209.00136 -133.39064)
		(end 207.279748 -133.39064)
		(width 0.127)
		(layer "In15.Cu")
		(net "FM_CPU0_SKTOCC_LVT3_N")
	)
	(segment
		(start 430.11725 -132.640578)
		(end 428.20971 -132.640578)
		(width 0.127)
		(layer "In15.Cu")
		(net "FM_CPU0_SKTOCC_LVT3_N")
	)
	(segment
		(start 415.487612 -130.69316)
		(end 409.9687 -125.174248)
		(width 0.127)
		(layer "In15.Cu")
		(net "FM_CPU0_SKTOCC_LVT3_N")
	)
	(segment
		(start 421.40632 -130.69316)
		(end 415.487612 -130.69316)
		(width 0.127)
		(layer "In15.Cu")
		(net "FM_CPU0_SKTOCC_LVT3_N")
	)
	(segment
		(start 191.229234 -133.157468)
		(end 190.462154 -133.157468)
		(width 0.127)
		(layer "In15.Cu")
		(net "FM_CPU0_SKTOCC_LVT3_N")
	)
	(segment
		(start 205.28534 -135.385048)
		(end 196.05498 -135.385048)
		(width 0.127)
		(layer "In15.Cu")
		(net "FM_CPU0_SKTOCC_LVT3_N")
	)
	(segment
		(start 432.895248 -173.59376)
		(end 437.30672 -169.182288)
		(width 0.127)
		(layer "In15.Cu")
		(net "FM_CPU0_SKTOCC_LVT3_N")
	)
	(segment
		(start 181.656736 -132.951728)
		(end 181.436772 -133.171692)
		(width 0.127)
		(layer "In15.Cu")
		(net "FM_CPU0_SKTOCC_LVT3_N")
	)
	(segment
		(start 184.366408 -132.579364)
		(end 183.994044 -132.951728)
		(width 0.127)
		(layer "In15.Cu")
		(net "FM_CPU0_SKTOCC_LVT3_N")
	)
	(segment
		(start 422.300908 -131.587748)
		(end 421.40632 -130.69316)
		(width 0.127)
		(layer "In15.Cu")
		(net "FM_CPU0_SKTOCC_LVT3_N")
	)
	(segment
		(start 188.583824 -131.111498)
		(end 187.36437 -129.892044)
		(width 0.127)
		(layer "In15.Cu")
		(net "FM_CPU0_SKTOCC_LVT3_N")
	)
	(segment
		(start 177.15865 -131.853178)
		(end 176.58588 -131.280408)
		(width 0.127)
		(layer "In15.Cu")
		(net "FM_CPU0_SKTOCC_LVT3_N")
	)
	(segment
		(start 425.567602 -180.786786)
		(end 431.374042 -180.786786)
		(width 0.127)
		(layer "In15.Cu")
		(net "FM_CPU0_SKTOCC_LVT3_N")
	)
	(segment
		(start 179.755546 -118.575328)
		(end 180.155596 -118.975378)
		(width 0.12954)
		(layer "F.Cu")
		(net "FM_CPU0_PROC_ID1")
	)
	(segment
		(start 186.74588 -129.866898)
		(end 186.74588 -129.250948)
		(width 0.12954)
		(layer "F.Cu")
		(net "FM_CPU0_PROC_ID1")
	)
	(segment
		(start 354.991162 -272.917158)
		(end 354.991162 -273.452844)
		(width 0.12954)
		(layer "F.Cu")
		(net "FM_CPU0_PROC_ID1")
	)
	(segment
		(start 354.991162 -273.452844)
		(end 354.991416 -273.453098)
		(width 0.12954)
		(layer "F.Cu")
		(net "FM_CPU0_PROC_ID1")
	)
	(via
		(at 186.74588 -129.250948)
		(size 0.508)
		(drill 0.254)
		(layers "F.Cu" "B.Cu")
		(net "FM_CPU0_PROC_ID1")
	)
	(via
		(at 354.991416 -273.453098)
		(size 0.4572)
		(drill 0.2032)
		(layers "F.Cu" "B.Cu")
		(net "FM_CPU0_PROC_ID1")
	)
	(via
		(at 180.155596 -118.975378)
		(size 0.4572)
		(drill 0.254)
		(layers "F.Cu" "B.Cu")
		(net "FM_CPU0_PROC_ID1")
	)
	(via
		(at 200.58888 -149.189948)
		(size 0.508)
		(drill 0.254)
		(layers "F.Cu" "B.Cu")
		(net "FM_CPU0_PROC_ID1")
	)
	(via
		(at 316.992 -276.789642)
		(size 0.6604)
		(drill 0.3302)
		(layers "F.Cu" "B.Cu")
		(net "FM_CPU0_PROC_ID1")
	)
	(segment
		(start 354.253546 -273.76882)
		(end 354.238814 -273.777456)
		(width 0.0889)
		(layer "B.Cu")
		(net "FM_CPU0_PROC_ID1")
	)
	(segment
		(start 298.599606 -276.76983)
		(end 298.429426 -276.59965)
		(width 0.12954)
		(layer "B.Cu")
		(net "FM_CPU0_PROC_ID1")
	)
	(segment
		(start 292.2651 -277.00859)
		(end 290.81984 -275.56333)
		(width 0.12954)
		(layer "B.Cu")
		(net "FM_CPU0_PROC_ID1")
	)
	(segment
		(start 290.176458 -275.56333)
		(end 286.282638 -271.66951)
		(width 0.12954)
		(layer "B.Cu")
		(net "FM_CPU0_PROC_ID1")
	)
	(segment
		(start 333.750158 -275.065236)
		(end 333.750158 -275.571458)
		(width 0.0889)
		(layer "B.Cu")
		(net "FM_CPU0_PROC_ID1")
	)
	(segment
		(start 242.90528 -169.484548)
		(end 242.90528 -162.32632)
		(width 0.12954)
		(layer "B.Cu")
		(net "FM_CPU0_PROC_ID1")
	)
	(segment
		(start 315.14923 -276.789642)
		(end 315.111638 -276.75205)
		(width 0.12954)
		(layer "B.Cu")
		(net "FM_CPU0_PROC_ID1")
	)
	(segment
		(start 284.39364 -256.582672)
		(end 279.191974 -256.582672)
		(width 0.12954)
		(layer "B.Cu")
		(net "FM_CPU0_PROC_ID1")
	)
	(segment
		(start 272.739358 -197.916038)
		(end 272.739358 -192.23101)
		(width 0.12954)
		(layer "B.Cu")
		(net "FM_CPU0_PROC_ID1")
	)
	(segment
		(start 286.282638 -266.85367)
		(end 286.061658 -266.63269)
		(width 0.12954)
		(layer "B.Cu")
		(net "FM_CPU0_PROC_ID1")
	)
	(segment
		(start 275.683218 -251.828808)
		(end 275.683218 -247.17883)
		(width 0.12954)
		(layer "B.Cu")
		(net "FM_CPU0_PROC_ID1")
	)
	(segment
		(start 274.690078 -246.18569)
		(end 274.690078 -199.866758)
		(width 0.12954)
		(layer "B.Cu")
		(net "FM_CPU0_PROC_ID1")
	)
	(segment
		(start 315.111638 -276.75205)
		(end 311.575958 -276.75205)
		(width 0.12954)
		(layer "B.Cu")
		(net "FM_CPU0_PROC_ID1")
	)
	(segment
		(start 333.55026 -275.771356)
		(end 333.303626 -276.01799)
		(width 0.12954)
		(layer "B.Cu")
		(net "FM_CPU0_PROC_ID1")
	)
	(segment
		(start 279.191974 -256.582672)
		(end 276.563836 -253.954534)
		(width 0.12954)
		(layer "B.Cu")
		(net "FM_CPU0_PROC_ID1")
	)
	(segment
		(start 299.526198 -276.89937)
		(end 299.396658 -276.76983)
		(width 0.12954)
		(layer "B.Cu")
		(net "FM_CPU0_PROC_ID1")
	)
	(segment
		(start 307.583078 -277.58771)
		(end 307.379878 -277.79091)
		(width 0.12954)
		(layer "B.Cu")
		(net "FM_CPU0_PROC_ID1")
	)
	(segment
		(start 339.297518 -274.591272)
		(end 339.287104 -274.585176)
		(width 0.0889)
		(layer "B.Cu")
		(net "FM_CPU0_PROC_ID1")
	)
	(segment
		(start 290.81984 -275.56333)
		(end 290.176458 -275.56333)
		(width 0.12954)
		(layer "B.Cu")
		(net "FM_CPU0_PROC_ID1")
	)
	(segment
		(start 347.755464 -274.591272)
		(end 347.740732 -274.582636)
		(width 0.0889)
		(layer "B.Cu")
		(net "FM_CPU0_PROC_ID1")
	)
	(segment
		(start 286.061658 -258.25069)
		(end 284.39364 -256.582672)
		(width 0.12954)
		(layer "B.Cu")
		(net "FM_CPU0_PROC_ID1")
	)
	(segment
		(start 294.07993 -276.81809)
		(end 293.88943 -277.00859)
		(width 0.12954)
		(layer "B.Cu")
		(net "FM_CPU0_PROC_ID1")
	)
	(segment
		(start 286.061658 -266.63269)
		(end 286.061658 -258.25069)
		(width 0.12954)
		(layer "B.Cu")
		(net "FM_CPU0_PROC_ID1")
	)
	(segment
		(start 275.683218 -247.17883)
		(end 274.690078 -246.18569)
		(width 0.12954)
		(layer "B.Cu")
		(net "FM_CPU0_PROC_ID1")
	)
	(segment
		(start 199.99325 -149.658578)
		(end 200.46188 -149.189948)
		(width 0.12954)
		(layer "B.Cu")
		(net "FM_CPU0_PROC_ID1")
	)
	(segment
		(start 343.056464 -274.591272)
		(end 343.041732 -274.582636)
		(width 0.0889)
		(layer "B.Cu")
		(net "FM_CPU0_PROC_ID1")
	)
	(segment
		(start 199.99325 -152.656032)
		(end 199.99325 -149.658578)
		(width 0.12954)
		(layer "B.Cu")
		(net "FM_CPU0_PROC_ID1")
	)
	(segment
		(start 334.987392 -274.582636)
		(end 334.97266 -274.591272)
		(width 0.0889)
		(layer "B.Cu")
		(net "FM_CPU0_PROC_ID1")
	)
	(segment
		(start 345.875864 -274.591272)
		(end 345.861132 -274.582636)
		(width 0.0889)
		(layer "B.Cu")
		(net "FM_CPU0_PROC_ID1")
	)
	(segment
		(start 239.008158 -158.429198)
		(end 205.766416 -158.429198)
		(width 0.12954)
		(layer "B.Cu")
		(net "FM_CPU0_PROC_ID1")
	)
	(segment
		(start 326.226932 -276.789642)
		(end 316.992 -276.789642)
		(width 0.12954)
		(layer "B.Cu")
		(net "FM_CPU0_PROC_ID1")
	)
	(segment
		(start 354.834952 -273.724116)
		(end 354.745798 -273.747992)
		(width 0.0889)
		(layer "B.Cu")
		(net "FM_CPU0_PROC_ID1")
	)
	(segment
		(start 295.38295 -276.81809)
		(end 294.07993 -276.81809)
		(width 0.12954)
		(layer "B.Cu")
		(net "FM_CPU0_PROC_ID1")
	)
	(segment
		(start 351.136712 -274.257008)
		(end 351.136712 -274.266914)
		(width 0.0889)
		(layer "B.Cu")
		(net "FM_CPU0_PROC_ID1")
	)
	(segment
		(start 200.46188 -149.189948)
		(end 200.58888 -149.189948)
		(width 0.12954)
		(layer "B.Cu")
		(net "FM_CPU0_PROC_ID1")
	)
	(segment
		(start 250.653296 -170.144948)
		(end 243.56568 -170.144948)
		(width 0.12954)
		(layer "B.Cu")
		(net "FM_CPU0_PROC_ID1")
	)
	(segment
		(start 276.563836 -253.954534)
		(end 275.683218 -251.828808)
		(width 0.12954)
		(layer "B.Cu")
		(net "FM_CPU0_PROC_ID1")
	)
	(segment
		(start 205.766416 -158.429198)
		(end 199.99325 -152.656032)
		(width 0.12954)
		(layer "B.Cu")
		(net "FM_CPU0_PROC_ID1")
	)
	(segment
		(start 272.739358 -192.23101)
		(end 250.653296 -170.144948)
		(width 0.12954)
		(layer "B.Cu")
		(net "FM_CPU0_PROC_ID1")
	)
	(segment
		(start 343.996264 -274.591272)
		(end 343.981532 -274.582636)
		(width 0.0889)
		(layer "B.Cu")
		(net "FM_CPU0_PROC_ID1")
	)
	(segment
		(start 310.740298 -277.58771)
		(end 307.583078 -277.58771)
		(width 0.12954)
		(layer "B.Cu")
		(net "FM_CPU0_PROC_ID1")
	)
	(segment
		(start 307.379878 -277.79091)
		(end 303.547018 -277.79091)
		(width 0.12954)
		(layer "B.Cu")
		(net "FM_CPU0_PROC_ID1")
	)
	(segment
		(start 298.429426 -276.59965)
		(end 295.60139 -276.59965)
		(width 0.12954)
		(layer "B.Cu")
		(net "FM_CPU0_PROC_ID1")
	)
	(segment
		(start 339.682328 -274.585176)
		(end 339.671914 -274.591272)
		(width 0.0889)
		(layer "B.Cu")
		(net "FM_CPU0_PROC_ID1")
	)
	(segment
		(start 350.95815 -274.586192)
		(end 350.94926 -274.591272)
		(width 0.0889)
		(layer "B.Cu")
		(net "FM_CPU0_PROC_ID1")
	)
	(segment
		(start 286.282638 -271.66951)
		(end 286.282638 -266.85367)
		(width 0.12954)
		(layer "B.Cu")
		(net "FM_CPU0_PROC_ID1")
	)
	(segment
		(start 348.695264 -274.591272)
		(end 348.680532 -274.582636)
		(width 0.0889)
		(layer "B.Cu")
		(net "FM_CPU0_PROC_ID1")
	)
	(segment
		(start 333.750158 -275.571458)
		(end 333.55026 -275.771356)
		(width 0.0889)
		(layer "B.Cu")
		(net "FM_CPU0_PROC_ID1")
	)
	(segment
		(start 333.303626 -276.01799)
		(end 326.998584 -276.01799)
		(width 0.12954)
		(layer "B.Cu")
		(net "FM_CPU0_PROC_ID1")
	)
	(segment
		(start 311.575958 -276.75205)
		(end 310.740298 -277.58771)
		(width 0.12954)
		(layer "B.Cu")
		(net "FM_CPU0_PROC_ID1")
	)
	(segment
		(start 350.574864 -274.591272)
		(end 350.560132 -274.582636)
		(width 0.0889)
		(layer "B.Cu")
		(net "FM_CPU0_PROC_ID1")
	)
	(segment
		(start 243.56568 -170.144948)
		(end 242.90528 -169.484548)
		(width 0.12954)
		(layer "B.Cu")
		(net "FM_CPU0_PROC_ID1")
	)
	(segment
		(start 354.991416 -273.453098)
		(end 354.834952 -273.724116)
		(width 0.0889)
		(layer "B.Cu")
		(net "FM_CPU0_PROC_ID1")
	)
	(segment
		(start 353.313746 -273.76882)
		(end 353.299014 -273.777456)
		(width 0.0889)
		(layer "B.Cu")
		(net "FM_CPU0_PROC_ID1")
	)
	(segment
		(start 293.88943 -277.00859)
		(end 292.2651 -277.00859)
		(width 0.12954)
		(layer "B.Cu")
		(net "FM_CPU0_PROC_ID1")
	)
	(segment
		(start 303.547018 -277.79091)
		(end 302.655478 -276.89937)
		(width 0.12954)
		(layer "B.Cu")
		(net "FM_CPU0_PROC_ID1")
	)
	(segment
		(start 316.992 -276.789642)
		(end 315.14923 -276.789642)
		(width 0.12954)
		(layer "B.Cu")
		(net "FM_CPU0_PROC_ID1")
	)
	(segment
		(start 349.635064 -274.591272)
		(end 349.620332 -274.582636)
		(width 0.0889)
		(layer "B.Cu")
		(net "FM_CPU0_PROC_ID1")
	)
	(segment
		(start 326.998584 -276.01799)
		(end 326.226932 -276.789642)
		(width 0.12954)
		(layer "B.Cu")
		(net "FM_CPU0_PROC_ID1")
	)
	(segment
		(start 299.396658 -276.76983)
		(end 298.599606 -276.76983)
		(width 0.12954)
		(layer "B.Cu")
		(net "FM_CPU0_PROC_ID1")
	)
	(segment
		(start 342.116664 -274.591272)
		(end 342.101932 -274.582636)
		(width 0.0889)
		(layer "B.Cu")
		(net "FM_CPU0_PROC_ID1")
	)
	(segment
		(start 341.176864 -274.591272)
		(end 341.162132 -274.582636)
		(width 0.0889)
		(layer "B.Cu")
		(net "FM_CPU0_PROC_ID1")
	)
	(segment
		(start 352.373946 -273.76882)
		(end 352.359214 -273.777456)
		(width 0.0889)
		(layer "B.Cu")
		(net "FM_CPU0_PROC_ID1")
	)
	(segment
		(start 295.60139 -276.59965)
		(end 295.38295 -276.81809)
		(width 0.12954)
		(layer "B.Cu")
		(net "FM_CPU0_PROC_ID1")
	)
	(segment
		(start 242.90528 -162.32632)
		(end 239.008158 -158.429198)
		(width 0.12954)
		(layer "B.Cu")
		(net "FM_CPU0_PROC_ID1")
	)
	(segment
		(start 302.655478 -276.89937)
		(end 299.526198 -276.89937)
		(width 0.12954)
		(layer "B.Cu")
		(net "FM_CPU0_PROC_ID1")
	)
	(segment
		(start 351.429574 -273.77136)
		(end 351.41916 -273.777456)
		(width 0.0889)
		(layer "B.Cu")
		(net "FM_CPU0_PROC_ID1")
	)
	(segment
		(start 344.936064 -274.591272)
		(end 344.921332 -274.582636)
		(width 0.0889)
		(layer "B.Cu")
		(net "FM_CPU0_PROC_ID1")
	)
	(segment
		(start 274.690078 -199.866758)
		(end 272.739358 -197.916038)
		(width 0.12954)
		(layer "B.Cu")
		(net "FM_CPU0_PROC_ID1")
	)
	(arc
		(start 351.984818 -273.777456)
		(mid 351.708005 -273.701586)
		(end 351.429574 -273.77136)
		(width 0.0889)
		(layer "B.Cu")
		(net "FM_CPU0_PROC_ID1")
	)
	(arc
		(start 338.357464 -274.591272)
		(mid 338.074762 -274.515496)
		(end 337.79206 -274.591272)
		(width 0.0889)
		(layer "B.Cu")
		(net "FM_CPU0_PROC_ID1")
	)
	(arc
		(start 342.101932 -274.582636)
		(mid 341.825457 -274.515316)
		(end 341.55126 -274.591272)
		(width 0.0889)
		(layer "B.Cu")
		(net "FM_CPU0_PROC_ID1")
	)
	(arc
		(start 337.417664 -274.591272)
		(mid 337.134962 -274.515496)
		(end 336.85226 -274.591272)
		(width 0.0889)
		(layer "B.Cu")
		(net "FM_CPU0_PROC_ID1")
	)
	(arc
		(start 350.94926 -274.591272)
		(mid 350.762062 -274.641415)
		(end 350.574864 -274.591272)
		(width 0.0889)
		(layer "B.Cu")
		(net "FM_CPU0_PROC_ID1")
	)
	(arc
		(start 347.19006 -274.591272)
		(mid 347.002862 -274.641415)
		(end 346.815664 -274.591272)
		(width 0.0889)
		(layer "B.Cu")
		(net "FM_CPU0_PROC_ID1")
	)
	(arc
		(start 347.740732 -274.582636)
		(mid 347.464257 -274.515316)
		(end 347.19006 -274.591272)
		(width 0.0889)
		(layer "B.Cu")
		(net "FM_CPU0_PROC_ID1")
	)
	(arc
		(start 353.864418 -273.777456)
		(mid 353.590219 -273.701621)
		(end 353.313746 -273.76882)
		(width 0.0889)
		(layer "B.Cu")
		(net "FM_CPU0_PROC_ID1")
	)
	(arc
		(start 343.041732 -274.582636)
		(mid 342.765257 -274.515316)
		(end 342.49106 -274.591272)
		(width 0.0889)
		(layer "B.Cu")
		(net "FM_CPU0_PROC_ID1")
	)
	(arc
		(start 344.921332 -274.582636)
		(mid 344.644857 -274.515316)
		(end 344.37066 -274.591272)
		(width 0.0889)
		(layer "B.Cu")
		(net "FM_CPU0_PROC_ID1")
	)
	(arc
		(start 341.55126 -274.591272)
		(mid 341.364062 -274.641415)
		(end 341.176864 -274.591272)
		(width 0.0889)
		(layer "B.Cu")
		(net "FM_CPU0_PROC_ID1")
	)
	(arc
		(start 351.136712 -274.266914)
		(mid 351.089033 -274.449814)
		(end 350.95815 -274.586192)
		(width 0.0889)
		(layer "B.Cu")
		(net "FM_CPU0_PROC_ID1")
	)
	(arc
		(start 340.237064 -274.591272)
		(mid 339.960505 -274.515529)
		(end 339.682328 -274.585176)
		(width 0.0889)
		(layer "B.Cu")
		(net "FM_CPU0_PROC_ID1")
	)
	(arc
		(start 354.745798 -273.747992)
		(mid 354.497293 -273.702005)
		(end 354.253546 -273.76882)
		(width 0.0889)
		(layer "B.Cu")
		(net "FM_CPU0_PROC_ID1")
	)
	(arc
		(start 344.37066 -274.591272)
		(mid 344.183462 -274.641415)
		(end 343.996264 -274.591272)
		(width 0.0889)
		(layer "B.Cu")
		(net "FM_CPU0_PROC_ID1")
	)
	(arc
		(start 343.43086 -274.591272)
		(mid 343.243662 -274.641415)
		(end 343.056464 -274.591272)
		(width 0.0889)
		(layer "B.Cu")
		(net "FM_CPU0_PROC_ID1")
	)
	(arc
		(start 346.25026 -274.591272)
		(mid 346.063062 -274.641415)
		(end 345.875864 -274.591272)
		(width 0.0889)
		(layer "B.Cu")
		(net "FM_CPU0_PROC_ID1")
	)
	(arc
		(start 349.620332 -274.582636)
		(mid 349.343857 -274.515316)
		(end 349.06966 -274.591272)
		(width 0.0889)
		(layer "B.Cu")
		(net "FM_CPU0_PROC_ID1")
	)
	(arc
		(start 345.861132 -274.582636)
		(mid 345.584657 -274.515316)
		(end 345.31046 -274.591272)
		(width 0.0889)
		(layer "B.Cu")
		(net "FM_CPU0_PROC_ID1")
	)
	(arc
		(start 339.671914 -274.591272)
		(mid 339.484716 -274.641415)
		(end 339.297518 -274.591272)
		(width 0.0889)
		(layer "B.Cu")
		(net "FM_CPU0_PROC_ID1")
	)
	(arc
		(start 334.598264 -274.591272)
		(mid 334.039503 -274.587207)
		(end 333.750158 -275.065236)
		(width 0.0889)
		(layer "B.Cu")
		(net "FM_CPU0_PROC_ID1")
	)
	(arc
		(start 352.359214 -273.777456)
		(mid 352.172016 -273.827599)
		(end 351.984818 -273.777456)
		(width 0.0889)
		(layer "B.Cu")
		(net "FM_CPU0_PROC_ID1")
	)
	(arc
		(start 334.97266 -274.591272)
		(mid 334.785462 -274.641415)
		(end 334.598264 -274.591272)
		(width 0.0889)
		(layer "B.Cu")
		(net "FM_CPU0_PROC_ID1")
	)
	(arc
		(start 342.49106 -274.591272)
		(mid 342.303862 -274.641415)
		(end 342.116664 -274.591272)
		(width 0.0889)
		(layer "B.Cu")
		(net "FM_CPU0_PROC_ID1")
	)
	(arc
		(start 336.85226 -274.591272)
		(mid 336.665062 -274.641415)
		(end 336.477864 -274.591272)
		(width 0.0889)
		(layer "B.Cu")
		(net "FM_CPU0_PROC_ID1")
	)
	(arc
		(start 336.477864 -274.591272)
		(mid 336.195162 -274.515496)
		(end 335.91246 -274.591272)
		(width 0.0889)
		(layer "B.Cu")
		(net "FM_CPU0_PROC_ID1")
	)
	(arc
		(start 335.91246 -274.591272)
		(mid 335.725262 -274.641415)
		(end 335.538064 -274.591272)
		(width 0.0889)
		(layer "B.Cu")
		(net "FM_CPU0_PROC_ID1")
	)
	(arc
		(start 345.31046 -274.591272)
		(mid 345.123262 -274.641415)
		(end 344.936064 -274.591272)
		(width 0.0889)
		(layer "B.Cu")
		(net "FM_CPU0_PROC_ID1")
	)
	(arc
		(start 335.538064 -274.591272)
		(mid 335.263865 -274.515437)
		(end 334.987392 -274.582636)
		(width 0.0889)
		(layer "B.Cu")
		(net "FM_CPU0_PROC_ID1")
	)
	(arc
		(start 337.79206 -274.591272)
		(mid 337.604862 -274.641415)
		(end 337.417664 -274.591272)
		(width 0.0889)
		(layer "B.Cu")
		(net "FM_CPU0_PROC_ID1")
	)
	(arc
		(start 351.41916 -273.777456)
		(mid 351.214825 -273.980061)
		(end 351.136712 -274.257008)
		(width 0.0889)
		(layer "B.Cu")
		(net "FM_CPU0_PROC_ID1")
	)
	(arc
		(start 338.73186 -274.591272)
		(mid 338.544662 -274.641415)
		(end 338.357464 -274.591272)
		(width 0.0889)
		(layer "B.Cu")
		(net "FM_CPU0_PROC_ID1")
	)
	(arc
		(start 343.981532 -274.582636)
		(mid 343.705057 -274.515316)
		(end 343.43086 -274.591272)
		(width 0.0889)
		(layer "B.Cu")
		(net "FM_CPU0_PROC_ID1")
	)
	(arc
		(start 350.560132 -274.582636)
		(mid 350.283657 -274.515316)
		(end 350.00946 -274.591272)
		(width 0.0889)
		(layer "B.Cu")
		(net "FM_CPU0_PROC_ID1")
	)
	(arc
		(start 353.299014 -273.777456)
		(mid 353.111816 -273.827599)
		(end 352.924618 -273.777456)
		(width 0.0889)
		(layer "B.Cu")
		(net "FM_CPU0_PROC_ID1")
	)
	(arc
		(start 339.287104 -274.585176)
		(mid 339.008672 -274.51533)
		(end 338.73186 -274.591272)
		(width 0.0889)
		(layer "B.Cu")
		(net "FM_CPU0_PROC_ID1")
	)
	(arc
		(start 346.815664 -274.591272)
		(mid 346.532962 -274.515496)
		(end 346.25026 -274.591272)
		(width 0.0889)
		(layer "B.Cu")
		(net "FM_CPU0_PROC_ID1")
	)
	(arc
		(start 340.61146 -274.591272)
		(mid 340.424262 -274.641415)
		(end 340.237064 -274.591272)
		(width 0.0889)
		(layer "B.Cu")
		(net "FM_CPU0_PROC_ID1")
	)
	(arc
		(start 341.162132 -274.582636)
		(mid 340.885657 -274.515316)
		(end 340.61146 -274.591272)
		(width 0.0889)
		(layer "B.Cu")
		(net "FM_CPU0_PROC_ID1")
	)
	(arc
		(start 348.680532 -274.582636)
		(mid 348.404057 -274.515316)
		(end 348.12986 -274.591272)
		(width 0.0889)
		(layer "B.Cu")
		(net "FM_CPU0_PROC_ID1")
	)
	(arc
		(start 354.238814 -273.777456)
		(mid 354.051616 -273.827599)
		(end 353.864418 -273.777456)
		(width 0.0889)
		(layer "B.Cu")
		(net "FM_CPU0_PROC_ID1")
	)
	(arc
		(start 350.00946 -274.591272)
		(mid 349.822262 -274.641415)
		(end 349.635064 -274.591272)
		(width 0.0889)
		(layer "B.Cu")
		(net "FM_CPU0_PROC_ID1")
	)
	(arc
		(start 348.12986 -274.591272)
		(mid 347.942662 -274.641415)
		(end 347.755464 -274.591272)
		(width 0.0889)
		(layer "B.Cu")
		(net "FM_CPU0_PROC_ID1")
	)
	(arc
		(start 349.06966 -274.591272)
		(mid 348.882462 -274.641415)
		(end 348.695264 -274.591272)
		(width 0.0889)
		(layer "B.Cu")
		(net "FM_CPU0_PROC_ID1")
	)
	(arc
		(start 352.924618 -273.777456)
		(mid 352.650419 -273.701621)
		(end 352.373946 -273.76882)
		(width 0.0889)
		(layer "B.Cu")
		(net "FM_CPU0_PROC_ID1")
	)
	(segment
		(start 181.1528 -120.180608)
		(end 180.7337 -120.180608)
		(width 0.127)
		(layer "In2.Cu")
		(net "FM_CPU0_PROC_ID1")
	)
	(segment
		(start 186.13374 -129.863088)
		(end 186.74588 -129.250948)
		(width 0.127)
		(layer "In2.Cu")
		(net "FM_CPU0_PROC_ID1")
	)
	(segment
		(start 185.96356 -127.114808)
		(end 182.23738 -123.388628)
		(width 0.127)
		(layer "In2.Cu")
		(net "FM_CPU0_PROC_ID1")
	)
	(segment
		(start 185.73242 -134.06374)
		(end 186.13374 -133.66242)
		(width 0.127)
		(layer "In2.Cu")
		(net "FM_CPU0_PROC_ID1")
	)
	(segment
		(start 180.55336 -120.000268)
		(end 180.55336 -119.373142)
		(width 0.127)
		(layer "In2.Cu")
		(net "FM_CPU0_PROC_ID1")
	)
	(segment
		(start 196.77888 -146.624548)
		(end 189.737238 -146.624548)
		(width 0.127)
		(layer "In2.Cu")
		(net "FM_CPU0_PROC_ID1")
	)
	(segment
		(start 182.23738 -122.779028)
		(end 181.35092 -121.892568)
		(width 0.127)
		(layer "In2.Cu")
		(net "FM_CPU0_PROC_ID1")
	)
	(segment
		(start 189.737238 -146.624548)
		(end 185.73242 -142.61973)
		(width 0.127)
		(layer "In2.Cu")
		(net "FM_CPU0_PROC_ID1")
	)
	(segment
		(start 180.7337 -120.180608)
		(end 180.55336 -120.000268)
		(width 0.127)
		(layer "In2.Cu")
		(net "FM_CPU0_PROC_ID1")
	)
	(segment
		(start 199.087486 -148.933154)
		(end 196.77888 -146.624548)
		(width 0.127)
		(layer "In2.Cu")
		(net "FM_CPU0_PROC_ID1")
	)
	(segment
		(start 186.13374 -133.66242)
		(end 186.13374 -129.863088)
		(width 0.127)
		(layer "In2.Cu")
		(net "FM_CPU0_PROC_ID1")
	)
	(segment
		(start 200.58888 -149.189948)
		(end 199.7075 -149.189948)
		(width 0.127)
		(layer "In2.Cu")
		(net "FM_CPU0_PROC_ID1")
	)
	(segment
		(start 185.73242 -142.61973)
		(end 185.73242 -134.06374)
		(width 0.127)
		(layer "In2.Cu")
		(net "FM_CPU0_PROC_ID1")
	)
	(segment
		(start 181.35092 -120.378728)
		(end 181.1528 -120.180608)
		(width 0.127)
		(layer "In2.Cu")
		(net "FM_CPU0_PROC_ID1")
	)
	(segment
		(start 185.96356 -128.468628)
		(end 185.96356 -127.114808)
		(width 0.127)
		(layer "In2.Cu")
		(net "FM_CPU0_PROC_ID1")
	)
	(segment
		(start 180.55336 -119.373142)
		(end 180.155596 -118.975378)
		(width 0.127)
		(layer "In2.Cu")
		(net "FM_CPU0_PROC_ID1")
	)
	(segment
		(start 182.23738 -123.388628)
		(end 182.23738 -122.779028)
		(width 0.127)
		(layer "In2.Cu")
		(net "FM_CPU0_PROC_ID1")
	)
	(segment
		(start 199.7075 -149.189948)
		(end 199.087486 -148.933154)
		(width 0.127)
		(layer "In2.Cu")
		(net "FM_CPU0_PROC_ID1")
	)
	(segment
		(start 181.35092 -121.892568)
		(end 181.35092 -120.378728)
		(width 0.127)
		(layer "In2.Cu")
		(net "FM_CPU0_PROC_ID1")
	)
	(segment
		(start 186.74588 -129.250948)
		(end 185.96356 -128.468628)
		(width 0.127)
		(layer "In2.Cu")
		(net "FM_CPU0_PROC_ID1")
	)
	(segment
		(start 354.521516 -273.730974)
		(end 354.521516 -274.26666)
		(width 0.12954)
		(layer "F.Cu")
		(net "FM_CPU0_PROC_ID0")
	)
	(segment
		(start 189.8904 -128.674368)
		(end 189.28588 -129.278888)
		(width 0.12954)
		(layer "F.Cu")
		(net "FM_CPU0_PROC_ID0")
	)
	(segment
		(start 189.28588 -129.278888)
		(end 189.28588 -129.866898)
		(width 0.12954)
		(layer "F.Cu")
		(net "FM_CPU0_PROC_ID0")
	)
	(segment
		(start 179.755546 -117.775482)
		(end 180.155596 -118.175532)
		(width 0.12954)
		(layer "F.Cu")
		(net "FM_CPU0_PROC_ID0")
	)
	(segment
		(start 354.521516 -274.26666)
		(end 354.521262 -274.266914)
		(width 0.12954)
		(layer "F.Cu")
		(net "FM_CPU0_PROC_ID0")
	)
	(via
		(at 180.155596 -118.175532)
		(size 0.4572)
		(drill 0.254)
		(layers "F.Cu" "B.Cu")
		(net "FM_CPU0_PROC_ID0")
	)
	(via
		(at 354.521262 -274.266914)
		(size 0.4572)
		(drill 0.2032)
		(layers "F.Cu" "B.Cu")
		(net "FM_CPU0_PROC_ID0")
	)
	(via
		(at 322.856098 -277.6347)
		(size 0.6604)
		(drill 0.3302)
		(layers "F.Cu" "B.Cu")
		(net "FM_CPU0_PROC_ID0")
	)
	(via
		(at 199.44588 -147.665948)
		(size 0.508)
		(drill 0.254)
		(layers "F.Cu" "B.Cu")
		(net "FM_CPU0_PROC_ID0")
	)
	(via
		(at 189.8904 -128.674368)
		(size 0.508)
		(drill 0.254)
		(layers "F.Cu" "B.Cu")
		(net "FM_CPU0_PROC_ID0")
	)
	(segment
		(start 341.096346 -274.765008)
		(end 341.081614 -274.756372)
		(width 0.0889)
		(layer "B.Cu")
		(net "FM_CPU0_PROC_ID0")
	)
	(segment
		(start 322.856098 -277.6347)
		(end 322.079874 -277.6347)
		(width 0.12954)
		(layer "B.Cu")
		(net "FM_CPU0_PROC_ID0")
	)
	(segment
		(start 354.521262 -274.266914)
		(end 354.677726 -273.995896)
		(width 0.0889)
		(layer "B.Cu")
		(net "FM_CPU0_PROC_ID0")
	)
	(segment
		(start 321.949064 -277.76551)
		(end 312.139838 -277.76551)
		(width 0.12954)
		(layer "B.Cu")
		(net "FM_CPU0_PROC_ID0")
	)
	(segment
		(start 273.668998 -199.388222)
		(end 271.746218 -197.465442)
		(width 0.12954)
		(layer "B.Cu")
		(net "FM_CPU0_PROC_ID0")
	)
	(segment
		(start 344.855546 -274.765008)
		(end 344.840814 -274.756372)
		(width 0.0889)
		(layer "B.Cu")
		(net "FM_CPU0_PROC_ID0")
	)
	(segment
		(start 285.645098 -258.376674)
		(end 284.234636 -256.966212)
		(width 0.12954)
		(layer "B.Cu")
		(net "FM_CPU0_PROC_ID0")
	)
	(segment
		(start 333.28864 -276.48027)
		(end 327.280778 -276.48027)
		(width 0.12954)
		(layer "B.Cu")
		(net "FM_CPU0_PROC_ID0")
	)
	(segment
		(start 250.593352 -170.627548)
		(end 243.38788 -170.627548)
		(width 0.12954)
		(layer "B.Cu")
		(net "FM_CPU0_PROC_ID0")
	)
	(segment
		(start 311.133998 -278.77135)
		(end 307.212238 -278.77135)
		(width 0.12954)
		(layer "B.Cu")
		(net "FM_CPU0_PROC_ID0")
	)
	(segment
		(start 205.607412 -158.812738)
		(end 199.44588 -152.651206)
		(width 0.12954)
		(layer "B.Cu")
		(net "FM_CPU0_PROC_ID0")
	)
	(segment
		(start 348.614746 -274.765008)
		(end 348.600014 -274.756372)
		(width 0.0889)
		(layer "B.Cu")
		(net "FM_CPU0_PROC_ID0")
	)
	(segment
		(start 338.272374 -274.762468)
		(end 338.26196 -274.756372)
		(width 0.0889)
		(layer "B.Cu")
		(net "FM_CPU0_PROC_ID0")
	)
	(segment
		(start 351.327212 -274.266914)
		(end 351.327212 -274.282408)
		(width 0.0889)
		(layer "B.Cu")
		(net "FM_CPU0_PROC_ID0")
	)
	(segment
		(start 333.77378 -275.99513)
		(end 333.28864 -276.48027)
		(width 0.12954)
		(layer "B.Cu")
		(net "FM_CPU0_PROC_ID0")
	)
	(segment
		(start 333.940658 -275.08073)
		(end 333.940658 -275.828252)
		(width 0.0889)
		(layer "B.Cu")
		(net "FM_CPU0_PROC_ID0")
	)
	(segment
		(start 271.746218 -191.780414)
		(end 250.593352 -170.627548)
		(width 0.12954)
		(layer "B.Cu")
		(net "FM_CPU0_PROC_ID0")
	)
	(segment
		(start 312.139838 -277.76551)
		(end 311.133998 -278.77135)
		(width 0.12954)
		(layer "B.Cu")
		(net "FM_CPU0_PROC_ID0")
	)
	(segment
		(start 306.828698 -278.38781)
		(end 303.432718 -278.38781)
		(width 0.12954)
		(layer "B.Cu")
		(net "FM_CPU0_PROC_ID0")
	)
	(segment
		(start 354.334064 -273.942556)
		(end 354.319332 -273.951192)
		(width 0.0889)
		(layer "B.Cu")
		(net "FM_CPU0_PROC_ID0")
	)
	(segment
		(start 345.791028 -274.762468)
		(end 345.780614 -274.756372)
		(width 0.0889)
		(layer "B.Cu")
		(net "FM_CPU0_PROC_ID0")
	)
	(segment
		(start 334.502506 -274.756372)
		(end 334.493616 -274.751292)
		(width 0.0889)
		(layer "B.Cu")
		(net "FM_CPU0_PROC_ID0")
	)
	(segment
		(start 347.674946 -274.765008)
		(end 347.660214 -274.756372)
		(width 0.0889)
		(layer "B.Cu")
		(net "FM_CPU0_PROC_ID0")
	)
	(segment
		(start 295.681908 -277.99411)
		(end 295.308528 -277.62073)
		(width 0.12954)
		(layer "B.Cu")
		(net "FM_CPU0_PROC_ID0")
	)
	(segment
		(start 199.44588 -152.651206)
		(end 199.44588 -147.665948)
		(width 0.12954)
		(layer "B.Cu")
		(net "FM_CPU0_PROC_ID0")
	)
	(segment
		(start 279.03297 -256.966212)
		(end 276.069806 -254.003048)
		(width 0.12954)
		(layer "B.Cu")
		(net "FM_CPU0_PROC_ID0")
	)
	(segment
		(start 340.151974 -274.762468)
		(end 340.14156 -274.756372)
		(width 0.0889)
		(layer "B.Cu")
		(net "FM_CPU0_PROC_ID0")
	)
	(segment
		(start 276.069806 -254.003048)
		(end 275.299678 -252.143514)
		(width 0.12954)
		(layer "B.Cu")
		(net "FM_CPU0_PROC_ID0")
	)
	(segment
		(start 327.280778 -276.48027)
		(end 326.126348 -277.6347)
		(width 0.12954)
		(layer "B.Cu")
		(net "FM_CPU0_PROC_ID0")
	)
	(segment
		(start 346.730574 -274.762468)
		(end 346.72016 -274.756372)
		(width 0.0889)
		(layer "B.Cu")
		(net "FM_CPU0_PROC_ID0")
	)
	(segment
		(start 302.492918 -277.44801)
		(end 299.561504 -277.44801)
		(width 0.12954)
		(layer "B.Cu")
		(net "FM_CPU0_PROC_ID0")
	)
	(segment
		(start 342.975946 -274.765008)
		(end 342.961214 -274.756372)
		(width 0.0889)
		(layer "B.Cu")
		(net "FM_CPU0_PROC_ID0")
	)
	(segment
		(start 242.27028 -162.233864)
		(end 238.849154 -158.812738)
		(width 0.12954)
		(layer "B.Cu")
		(net "FM_CPU0_PROC_ID0")
	)
	(segment
		(start 352.454464 -273.942556)
		(end 352.439732 -273.951192)
		(width 0.0889)
		(layer "B.Cu")
		(net "FM_CPU0_PROC_ID0")
	)
	(segment
		(start 354.677726 -273.995896)
		(end 354.656644 -273.917918)
		(width 0.0889)
		(layer "B.Cu")
		(net "FM_CPU0_PROC_ID0")
	)
	(segment
		(start 343.915746 -274.765008)
		(end 343.901014 -274.756372)
		(width 0.0889)
		(layer "B.Cu")
		(net "FM_CPU0_PROC_ID0")
	)
	(segment
		(start 322.079874 -277.6347)
		(end 321.949064 -277.76551)
		(width 0.12954)
		(layer "B.Cu")
		(net "FM_CPU0_PROC_ID0")
	)
	(segment
		(start 294.188388 -277.62073)
		(end 294.091868 -277.52421)
		(width 0.12954)
		(layer "B.Cu")
		(net "FM_CPU0_PROC_ID0")
	)
	(segment
		(start 275.299678 -247.61571)
		(end 273.668998 -245.98503)
		(width 0.12954)
		(layer "B.Cu")
		(net "FM_CPU0_PROC_ID0")
	)
	(segment
		(start 342.036146 -274.765008)
		(end 342.021414 -274.756372)
		(width 0.0889)
		(layer "B.Cu")
		(net "FM_CPU0_PROC_ID0")
	)
	(segment
		(start 333.940658 -275.828252)
		(end 333.77378 -275.99513)
		(width 0.0889)
		(layer "B.Cu")
		(net "FM_CPU0_PROC_ID0")
	)
	(segment
		(start 349.554546 -274.765008)
		(end 349.539814 -274.756372)
		(width 0.0889)
		(layer "B.Cu")
		(net "FM_CPU0_PROC_ID0")
	)
	(segment
		(start 243.38788 -170.627548)
		(end 242.27028 -169.509948)
		(width 0.12954)
		(layer "B.Cu")
		(net "FM_CPU0_PROC_ID0")
	)
	(segment
		(start 284.234636 -256.966212)
		(end 279.03297 -256.966212)
		(width 0.12954)
		(layer "B.Cu")
		(net "FM_CPU0_PROC_ID0")
	)
	(segment
		(start 298.468288 -277.67153)
		(end 298.145708 -277.99411)
		(width 0.12954)
		(layer "B.Cu")
		(net "FM_CPU0_PROC_ID0")
	)
	(segment
		(start 294.091868 -277.52421)
		(end 292.043358 -277.52421)
		(width 0.12954)
		(layer "B.Cu")
		(net "FM_CPU0_PROC_ID0")
	)
	(segment
		(start 298.145708 -277.99411)
		(end 295.681908 -277.99411)
		(width 0.12954)
		(layer "B.Cu")
		(net "FM_CPU0_PROC_ID0")
	)
	(segment
		(start 285.645098 -272.85569)
		(end 285.645098 -258.376674)
		(width 0.12954)
		(layer "B.Cu")
		(net "FM_CPU0_PROC_ID0")
	)
	(segment
		(start 335.06791 -274.756372)
		(end 335.053178 -274.765008)
		(width 0.0889)
		(layer "B.Cu")
		(net "FM_CPU0_PROC_ID0")
	)
	(segment
		(start 273.668998 -245.98503)
		(end 273.668998 -199.388222)
		(width 0.12954)
		(layer "B.Cu")
		(net "FM_CPU0_PROC_ID0")
	)
	(segment
		(start 242.27028 -169.509948)
		(end 242.27028 -162.233864)
		(width 0.12954)
		(layer "B.Cu")
		(net "FM_CPU0_PROC_ID0")
	)
	(segment
		(start 299.337984 -277.67153)
		(end 298.468288 -277.67153)
		(width 0.12954)
		(layer "B.Cu")
		(net "FM_CPU0_PROC_ID0")
	)
	(segment
		(start 303.432718 -278.38781)
		(end 302.492918 -277.44801)
		(width 0.12954)
		(layer "B.Cu")
		(net "FM_CPU0_PROC_ID0")
	)
	(segment
		(start 307.212238 -278.77135)
		(end 306.828698 -278.38781)
		(width 0.12954)
		(layer "B.Cu")
		(net "FM_CPU0_PROC_ID0")
	)
	(segment
		(start 335.44256 -274.756372)
		(end 335.442306 -274.756372)
		(width 0.0889)
		(layer "B.Cu")
		(net "FM_CPU0_PROC_ID0")
	)
	(segment
		(start 275.299678 -252.143514)
		(end 275.299678 -247.61571)
		(width 0.12954)
		(layer "B.Cu")
		(net "FM_CPU0_PROC_ID0")
	)
	(segment
		(start 351.514664 -273.942556)
		(end 351.505774 -273.947636)
		(width 0.0889)
		(layer "B.Cu")
		(net "FM_CPU0_PROC_ID0")
	)
	(segment
		(start 291.662358 -277.90521)
		(end 290.694618 -277.90521)
		(width 0.12954)
		(layer "B.Cu")
		(net "FM_CPU0_PROC_ID0")
	)
	(segment
		(start 350.494346 -274.765008)
		(end 350.479614 -274.756372)
		(width 0.0889)
		(layer "B.Cu")
		(net "FM_CPU0_PROC_ID0")
	)
	(segment
		(start 299.561504 -277.44801)
		(end 299.337984 -277.67153)
		(width 0.12954)
		(layer "B.Cu")
		(net "FM_CPU0_PROC_ID0")
	)
	(segment
		(start 353.394264 -273.942556)
		(end 353.379532 -273.951192)
		(width 0.0889)
		(layer "B.Cu")
		(net "FM_CPU0_PROC_ID0")
	)
	(segment
		(start 326.126348 -277.6347)
		(end 322.856098 -277.6347)
		(width 0.12954)
		(layer "B.Cu")
		(net "FM_CPU0_PROC_ID0")
	)
	(segment
		(start 271.746218 -197.465442)
		(end 271.746218 -191.780414)
		(width 0.12954)
		(layer "B.Cu")
		(net "FM_CPU0_PROC_ID0")
	)
	(segment
		(start 238.849154 -158.812738)
		(end 205.607412 -158.812738)
		(width 0.12954)
		(layer "B.Cu")
		(net "FM_CPU0_PROC_ID0")
	)
	(segment
		(start 339.767164 -274.756372)
		(end 339.75675 -274.762468)
		(width 0.0889)
		(layer "B.Cu")
		(net "FM_CPU0_PROC_ID0")
	)
	(segment
		(start 295.308528 -277.62073)
		(end 294.188388 -277.62073)
		(width 0.12954)
		(layer "B.Cu")
		(net "FM_CPU0_PROC_ID0")
	)
	(segment
		(start 292.043358 -277.52421)
		(end 291.662358 -277.90521)
		(width 0.12954)
		(layer "B.Cu")
		(net "FM_CPU0_PROC_ID0")
	)
	(segment
		(start 290.694618 -277.90521)
		(end 285.645098 -272.85569)
		(width 0.12954)
		(layer "B.Cu")
		(net "FM_CPU0_PROC_ID0")
	)
	(arc
		(start 336.947764 -274.756372)
		(mid 336.665062 -274.832148)
		(end 336.38236 -274.756372)
		(width 0.0889)
		(layer "B.Cu")
		(net "FM_CPU0_PROC_ID0")
	)
	(arc
		(start 350.479614 -274.756372)
		(mid 350.292416 -274.706229)
		(end 350.105218 -274.756372)
		(width 0.0889)
		(layer "B.Cu")
		(net "FM_CPU0_PROC_ID0")
	)
	(arc
		(start 346.72016 -274.756372)
		(mid 346.532962 -274.706229)
		(end 346.345764 -274.756372)
		(width 0.0889)
		(layer "B.Cu")
		(net "FM_CPU0_PROC_ID0")
	)
	(arc
		(start 354.319332 -273.951192)
		(mid 354.042857 -274.018512)
		(end 353.76866 -273.942556)
		(width 0.0889)
		(layer "B.Cu")
		(net "FM_CPU0_PROC_ID0")
	)
	(arc
		(start 340.14156 -274.756372)
		(mid 339.954362 -274.706229)
		(end 339.767164 -274.756372)
		(width 0.0889)
		(layer "B.Cu")
		(net "FM_CPU0_PROC_ID0")
	)
	(arc
		(start 337.32216 -274.756372)
		(mid 337.134962 -274.706229)
		(end 336.947764 -274.756372)
		(width 0.0889)
		(layer "B.Cu")
		(net "FM_CPU0_PROC_ID0")
	)
	(arc
		(start 351.045018 -274.756372)
		(mid 350.770819 -274.832207)
		(end 350.494346 -274.765008)
		(width 0.0889)
		(layer "B.Cu")
		(net "FM_CPU0_PROC_ID0")
	)
	(arc
		(start 348.600014 -274.756372)
		(mid 348.412816 -274.706229)
		(end 348.225618 -274.756372)
		(width 0.0889)
		(layer "B.Cu")
		(net "FM_CPU0_PROC_ID0")
	)
	(arc
		(start 341.647018 -274.756372)
		(mid 341.372819 -274.832207)
		(end 341.096346 -274.765008)
		(width 0.0889)
		(layer "B.Cu")
		(net "FM_CPU0_PROC_ID0")
	)
	(arc
		(start 343.526618 -274.756372)
		(mid 343.252419 -274.832207)
		(end 342.975946 -274.765008)
		(width 0.0889)
		(layer "B.Cu")
		(net "FM_CPU0_PROC_ID0")
	)
	(arc
		(start 335.053178 -274.765008)
		(mid 334.776703 -274.832328)
		(end 334.502506 -274.756372)
		(width 0.0889)
		(layer "B.Cu")
		(net "FM_CPU0_PROC_ID0")
	)
	(arc
		(start 353.76866 -273.942556)
		(mid 353.581462 -273.892413)
		(end 353.394264 -273.942556)
		(width 0.0889)
		(layer "B.Cu")
		(net "FM_CPU0_PROC_ID0")
	)
	(arc
		(start 338.827618 -274.756372)
		(mid 338.550805 -274.832242)
		(end 338.272374 -274.762468)
		(width 0.0889)
		(layer "B.Cu")
		(net "FM_CPU0_PROC_ID0")
	)
	(arc
		(start 336.38236 -274.756372)
		(mid 336.195162 -274.706229)
		(end 336.007964 -274.756372)
		(width 0.0889)
		(layer "B.Cu")
		(net "FM_CPU0_PROC_ID0")
	)
	(arc
		(start 336.007964 -274.756372)
		(mid 335.725262 -274.832148)
		(end 335.44256 -274.756372)
		(width 0.0889)
		(layer "B.Cu")
		(net "FM_CPU0_PROC_ID0")
	)
	(arc
		(start 344.466418 -274.756372)
		(mid 344.192219 -274.832207)
		(end 343.915746 -274.765008)
		(width 0.0889)
		(layer "B.Cu")
		(net "FM_CPU0_PROC_ID0")
	)
	(arc
		(start 342.586818 -274.756372)
		(mid 342.312619 -274.832207)
		(end 342.036146 -274.765008)
		(width 0.0889)
		(layer "B.Cu")
		(net "FM_CPU0_PROC_ID0")
	)
	(arc
		(start 344.840814 -274.756372)
		(mid 344.653616 -274.706229)
		(end 344.466418 -274.756372)
		(width 0.0889)
		(layer "B.Cu")
		(net "FM_CPU0_PROC_ID0")
	)
	(arc
		(start 354.656644 -273.917918)
		(mid 354.492548 -273.893571)
		(end 354.334064 -273.942556)
		(width 0.0889)
		(layer "B.Cu")
		(net "FM_CPU0_PROC_ID0")
	)
	(arc
		(start 349.539814 -274.756372)
		(mid 349.352616 -274.706229)
		(end 349.165418 -274.756372)
		(width 0.0889)
		(layer "B.Cu")
		(net "FM_CPU0_PROC_ID0")
	)
	(arc
		(start 347.285818 -274.756372)
		(mid 347.009005 -274.832242)
		(end 346.730574 -274.762468)
		(width 0.0889)
		(layer "B.Cu")
		(net "FM_CPU0_PROC_ID0")
	)
	(arc
		(start 345.406218 -274.756372)
		(mid 345.132019 -274.832207)
		(end 344.855546 -274.765008)
		(width 0.0889)
		(layer "B.Cu")
		(net "FM_CPU0_PROC_ID0")
	)
	(arc
		(start 339.75675 -274.762468)
		(mid 339.478572 -274.832191)
		(end 339.202014 -274.756372)
		(width 0.0889)
		(layer "B.Cu")
		(net "FM_CPU0_PROC_ID0")
	)
	(arc
		(start 353.379532 -273.951192)
		(mid 353.103057 -274.018512)
		(end 352.82886 -273.942556)
		(width 0.0889)
		(layer "B.Cu")
		(net "FM_CPU0_PROC_ID0")
	)
	(arc
		(start 339.202014 -274.756372)
		(mid 339.014816 -274.706229)
		(end 338.827618 -274.756372)
		(width 0.0889)
		(layer "B.Cu")
		(net "FM_CPU0_PROC_ID0")
	)
	(arc
		(start 346.345764 -274.756372)
		(mid 346.069205 -274.832115)
		(end 345.791028 -274.762468)
		(width 0.0889)
		(layer "B.Cu")
		(net "FM_CPU0_PROC_ID0")
	)
	(arc
		(start 352.439732 -273.951192)
		(mid 352.163257 -274.018512)
		(end 351.88906 -273.942556)
		(width 0.0889)
		(layer "B.Cu")
		(net "FM_CPU0_PROC_ID0")
	)
	(arc
		(start 349.165418 -274.756372)
		(mid 348.891219 -274.832207)
		(end 348.614746 -274.765008)
		(width 0.0889)
		(layer "B.Cu")
		(net "FM_CPU0_PROC_ID0")
	)
	(arc
		(start 334.493616 -274.751292)
		(mid 334.123567 -274.758925)
		(end 333.940658 -275.08073)
		(width 0.0889)
		(layer "B.Cu")
		(net "FM_CPU0_PROC_ID0")
	)
	(arc
		(start 347.660214 -274.756372)
		(mid 347.473016 -274.706229)
		(end 347.285818 -274.756372)
		(width 0.0889)
		(layer "B.Cu")
		(net "FM_CPU0_PROC_ID0")
	)
	(arc
		(start 348.225618 -274.756372)
		(mid 347.951419 -274.832207)
		(end 347.674946 -274.765008)
		(width 0.0889)
		(layer "B.Cu")
		(net "FM_CPU0_PROC_ID0")
	)
	(arc
		(start 335.442306 -274.756372)
		(mid 335.255108 -274.706229)
		(end 335.06791 -274.756372)
		(width 0.0889)
		(layer "B.Cu")
		(net "FM_CPU0_PROC_ID0")
	)
	(arc
		(start 342.021414 -274.756372)
		(mid 341.834216 -274.706229)
		(end 341.647018 -274.756372)
		(width 0.0889)
		(layer "B.Cu")
		(net "FM_CPU0_PROC_ID0")
	)
	(arc
		(start 351.88906 -273.942556)
		(mid 351.701862 -273.892413)
		(end 351.514664 -273.942556)
		(width 0.0889)
		(layer "B.Cu")
		(net "FM_CPU0_PROC_ID0")
	)
	(arc
		(start 338.26196 -274.756372)
		(mid 338.074762 -274.706229)
		(end 337.887564 -274.756372)
		(width 0.0889)
		(layer "B.Cu")
		(net "FM_CPU0_PROC_ID0")
	)
	(arc
		(start 342.961214 -274.756372)
		(mid 342.774016 -274.706229)
		(end 342.586818 -274.756372)
		(width 0.0889)
		(layer "B.Cu")
		(net "FM_CPU0_PROC_ID0")
	)
	(arc
		(start 351.327212 -274.282408)
		(mid 351.247842 -274.556142)
		(end 351.045018 -274.756372)
		(width 0.0889)
		(layer "B.Cu")
		(net "FM_CPU0_PROC_ID0")
	)
	(arc
		(start 345.780614 -274.756372)
		(mid 345.593416 -274.706229)
		(end 345.406218 -274.756372)
		(width 0.0889)
		(layer "B.Cu")
		(net "FM_CPU0_PROC_ID0")
	)
	(arc
		(start 337.887564 -274.756372)
		(mid 337.604862 -274.832148)
		(end 337.32216 -274.756372)
		(width 0.0889)
		(layer "B.Cu")
		(net "FM_CPU0_PROC_ID0")
	)
	(arc
		(start 343.901014 -274.756372)
		(mid 343.713816 -274.706229)
		(end 343.526618 -274.756372)
		(width 0.0889)
		(layer "B.Cu")
		(net "FM_CPU0_PROC_ID0")
	)
	(arc
		(start 351.505774 -273.947636)
		(mid 351.37486 -274.083996)
		(end 351.327212 -274.266914)
		(width 0.0889)
		(layer "B.Cu")
		(net "FM_CPU0_PROC_ID0")
	)
	(arc
		(start 352.82886 -273.942556)
		(mid 352.641662 -273.892413)
		(end 352.454464 -273.942556)
		(width 0.0889)
		(layer "B.Cu")
		(net "FM_CPU0_PROC_ID0")
	)
	(arc
		(start 350.105218 -274.756372)
		(mid 349.831019 -274.832207)
		(end 349.554546 -274.765008)
		(width 0.0889)
		(layer "B.Cu")
		(net "FM_CPU0_PROC_ID0")
	)
	(arc
		(start 341.081614 -274.756372)
		(mid 340.894416 -274.706229)
		(end 340.707218 -274.756372)
		(width 0.0889)
		(layer "B.Cu")
		(net "FM_CPU0_PROC_ID0")
	)
	(arc
		(start 340.707218 -274.756372)
		(mid 340.430405 -274.832242)
		(end 340.151974 -274.762468)
		(width 0.0889)
		(layer "B.Cu")
		(net "FM_CPU0_PROC_ID0")
	)
	(segment
		(start 189.15888 -127.183896)
		(end 189.8904 -127.915416)
		(width 0.127)
		(layer "In2.Cu")
		(net "FM_CPU0_PROC_ID0")
	)
	(segment
		(start 185.3565 -121.884948)
		(end 185.4708 -121.999248)
		(width 0.127)
		(layer "In2.Cu")
		(net "FM_CPU0_PROC_ID0")
	)
	(segment
		(start 199.44588 -147.665948)
		(end 190.33998 -138.560048)
		(width 0.127)
		(layer "In2.Cu")
		(net "FM_CPU0_PROC_ID0")
	)
	(segment
		(start 184.74944 -120.980708)
		(end 185.15838 -120.980708)
		(width 0.127)
		(layer "In2.Cu")
		(net "FM_CPU0_PROC_ID0")
	)
	(segment
		(start 182.38724 -119.370348)
		(end 183.55564 -119.370348)
		(width 0.127)
		(layer "In2.Cu")
		(net "FM_CPU0_PROC_ID0")
	)
	(segment
		(start 190.33998 -138.560048)
		(end 190.33998 -129.852928)
		(width 0.127)
		(layer "In2.Cu")
		(net "FM_CPU0_PROC_ID0")
	)
	(segment
		(start 181.93512 -118.580408)
		(end 182.1561 -118.801388)
		(width 0.127)
		(layer "In2.Cu")
		(net "FM_CPU0_PROC_ID0")
	)
	(segment
		(start 183.55564 -119.370348)
		(end 183.75376 -119.568468)
		(width 0.127)
		(layer "In2.Cu")
		(net "FM_CPU0_PROC_ID0")
	)
	(segment
		(start 180.155596 -118.175532)
		(end 180.560472 -118.580408)
		(width 0.127)
		(layer "In2.Cu")
		(net "FM_CPU0_PROC_ID0")
	)
	(segment
		(start 189.15888 -125.651768)
		(end 189.15888 -127.183896)
		(width 0.127)
		(layer "In2.Cu")
		(net "FM_CPU0_PROC_ID0")
	)
	(segment
		(start 180.560472 -118.580408)
		(end 181.93512 -118.580408)
		(width 0.127)
		(layer "In2.Cu")
		(net "FM_CPU0_PROC_ID0")
	)
	(segment
		(start 183.75376 -119.568468)
		(end 183.75376 -119.931688)
		(width 0.127)
		(layer "In2.Cu")
		(net "FM_CPU0_PROC_ID0")
	)
	(segment
		(start 185.4708 -122.679968)
		(end 187.1091 -124.318268)
		(width 0.127)
		(layer "In2.Cu")
		(net "FM_CPU0_PROC_ID0")
	)
	(segment
		(start 183.75376 -119.931688)
		(end 184.00014 -120.178068)
		(width 0.127)
		(layer "In2.Cu")
		(net "FM_CPU0_PROC_ID0")
	)
	(segment
		(start 182.1561 -119.139208)
		(end 182.38724 -119.370348)
		(width 0.127)
		(layer "In2.Cu")
		(net "FM_CPU0_PROC_ID0")
	)
	(segment
		(start 184.55386 -120.785128)
		(end 184.74944 -120.980708)
		(width 0.127)
		(layer "In2.Cu")
		(net "FM_CPU0_PROC_ID0")
	)
	(segment
		(start 184.36336 -120.178068)
		(end 184.55386 -120.368568)
		(width 0.127)
		(layer "In2.Cu")
		(net "FM_CPU0_PROC_ID0")
	)
	(segment
		(start 182.1561 -118.801388)
		(end 182.1561 -119.139208)
		(width 0.127)
		(layer "In2.Cu")
		(net "FM_CPU0_PROC_ID0")
	)
	(segment
		(start 184.00014 -120.178068)
		(end 184.36336 -120.178068)
		(width 0.127)
		(layer "In2.Cu")
		(net "FM_CPU0_PROC_ID0")
	)
	(segment
		(start 189.8904 -129.403348)
		(end 189.8904 -128.674368)
		(width 0.127)
		(layer "In2.Cu")
		(net "FM_CPU0_PROC_ID0")
	)
	(segment
		(start 184.55386 -120.368568)
		(end 184.55386 -120.785128)
		(width 0.127)
		(layer "In2.Cu")
		(net "FM_CPU0_PROC_ID0")
	)
	(segment
		(start 187.82538 -124.318268)
		(end 189.15888 -125.651768)
		(width 0.127)
		(layer "In2.Cu")
		(net "FM_CPU0_PROC_ID0")
	)
	(segment
		(start 189.8904 -127.915416)
		(end 189.8904 -128.674368)
		(width 0.127)
		(layer "In2.Cu")
		(net "FM_CPU0_PROC_ID0")
	)
	(segment
		(start 190.33998 -129.852928)
		(end 189.8904 -129.403348)
		(width 0.127)
		(layer "In2.Cu")
		(net "FM_CPU0_PROC_ID0")
	)
	(segment
		(start 187.1091 -124.318268)
		(end 187.82538 -124.318268)
		(width 0.127)
		(layer "In2.Cu")
		(net "FM_CPU0_PROC_ID0")
	)
	(segment
		(start 185.3565 -121.178828)
		(end 185.3565 -121.884948)
		(width 0.127)
		(layer "In2.Cu")
		(net "FM_CPU0_PROC_ID0")
	)
	(segment
		(start 185.4708 -121.999248)
		(end 185.4708 -122.679968)
		(width 0.127)
		(layer "In2.Cu")
		(net "FM_CPU0_PROC_ID0")
	)
	(segment
		(start 185.15838 -120.980708)
		(end 185.3565 -121.178828)
		(width 0.127)
		(layer "In2.Cu")
		(net "FM_CPU0_PROC_ID0")
	)
	(segment
		(start 184.41416 -126.787148)
		(end 184.19191 -126.564898)
		(width 0.12954)
		(layer "F.Cu")
		(net "FM_CPU0_PKGID2")
	)
	(segment
		(start 183.67248 -133.441948)
		(end 184.41416 -132.700268)
		(width 0.12954)
		(layer "F.Cu")
		(net "FM_CPU0_PKGID2")
	)
	(segment
		(start 182.93588 -124.087382)
		(end 181.355746 -122.507248)
		(width 0.12954)
		(layer "F.Cu")
		(net "FM_CPU0_PKGID2")
	)
	(segment
		(start 357.340662 -267.219938)
		(end 357.340662 -267.755878)
		(width 0.12954)
		(layer "F.Cu")
		(net "FM_CPU0_PKGID2")
	)
	(segment
		(start 183.69788 -125.603762)
		(end 183.435498 -125.34138)
		(width 0.12954)
		(layer "F.Cu")
		(net "FM_CPU0_PKGID2")
	)
	(segment
		(start 183.435498 -125.34138)
		(end 182.93588 -124.841762)
		(width 0.12954)
		(layer "F.Cu")
		(net "FM_CPU0_PKGID2")
	)
	(segment
		(start 184.41416 -132.700268)
		(end 184.41416 -126.787148)
		(width 0.12954)
		(layer "F.Cu")
		(net "FM_CPU0_PKGID2")
	)
	(segment
		(start 184.19191 -126.564898)
		(end 183.69788 -126.564898)
		(width 0.12954)
		(layer "F.Cu")
		(net "FM_CPU0_PKGID2")
	)
	(segment
		(start 181.355746 -122.507248)
		(end 181.355746 -121.775474)
		(width 0.12954)
		(layer "F.Cu")
		(net "FM_CPU0_PKGID2")
	)
	(segment
		(start 182.93588 -124.841762)
		(end 182.93588 -124.087382)
		(width 0.12954)
		(layer "F.Cu")
		(net "FM_CPU0_PKGID2")
	)
	(segment
		(start 183.69788 -126.564898)
		(end 183.69788 -125.603762)
		(width 0.12954)
		(layer "F.Cu")
		(net "FM_CPU0_PKGID2")
	)
	(via
		(at 318.403478 -275.96973)
		(size 0.6604)
		(drill 0.3302)
		(layers "F.Cu" "B.Cu")
		(net "FM_CPU0_PKGID2")
	)
	(via
		(at 183.67248 -133.441948)
		(size 0.508)
		(drill 0.254)
		(layers "F.Cu" "B.Cu")
		(net "FM_CPU0_PKGID2")
	)
	(via
		(at 200.58888 -149.824948)
		(size 0.508)
		(drill 0.254)
		(layers "F.Cu" "B.Cu")
		(net "FM_CPU0_PKGID2")
	)
	(via
		(at 357.340662 -267.755878)
		(size 0.4572)
		(drill 0.2032)
		(layers "F.Cu" "B.Cu")
		(net "FM_CPU0_PKGID2")
	)
	(via
		(at 183.435498 -125.34138)
		(size 0.762)
		(drill 0.381)
		(layers "F.Cu" "B.Cu")
		(net "FM_CPU0_PKGID2")
	)
	(segment
		(start 357.340662 -267.755878)
		(end 357.045514 -268.051026)
		(width 0.0889)
		(layer "B.Cu")
		(net "FM_CPU0_PKGID2")
	)
	(segment
		(start 298.113196 -276.10435)
		(end 295.73474 -276.10435)
		(width 0.12954)
		(layer "B.Cu")
		(net "FM_CPU0_PKGID2")
	)
	(segment
		(start 350.58096 -273.939)
		(end 350.574864 -273.942556)
		(width 0.0889)
		(layer "B.Cu")
		(net "FM_CPU0_PKGID2")
	)
	(segment
		(start 339.297518 -273.942556)
		(end 339.287104 -273.948652)
		(width 0.0889)
		(layer "B.Cu")
		(net "FM_CPU0_PKGID2")
	)
	(segment
		(start 287.423098 -271.24279)
		(end 286.666178 -270.48587)
		(width 0.12954)
		(layer "B.Cu")
		(net "FM_CPU0_PKGID2")
	)
	(segment
		(start 288.614358 -272.07845)
		(end 287.778698 -271.24279)
		(width 0.12954)
		(layer "B.Cu")
		(net "FM_CPU0_PKGID2")
	)
	(segment
		(start 345.875864 -273.942556)
		(end 345.861132 -273.951192)
		(width 0.0889)
		(layer "B.Cu")
		(net "FM_CPU0_PKGID2")
	)
	(segment
		(start 353.313746 -273.137376)
		(end 353.299014 -273.12874)
		(width 0.0889)
		(layer "B.Cu")
		(net "FM_CPU0_PKGID2")
	)
	(segment
		(start 273.127978 -192.006474)
		(end 239.146842 -158.025338)
		(width 0.12954)
		(layer "B.Cu")
		(net "FM_CPU0_PKGID2")
	)
	(segment
		(start 299.447458 -275.96719)
		(end 298.250356 -275.96719)
		(width 0.12954)
		(layer "B.Cu")
		(net "FM_CPU0_PKGID2")
	)
	(segment
		(start 355.273864 -270.687038)
		(end 355.264974 -270.692118)
		(width 0.0889)
		(layer "B.Cu")
		(net "FM_CPU0_PKGID2")
	)
	(segment
		(start 351.429574 -273.134836)
		(end 351.41916 -273.12874)
		(width 0.0889)
		(layer "B.Cu")
		(net "FM_CPU0_PKGID2")
	)
	(segment
		(start 311.405778 -276.35327)
		(end 310.631078 -277.12797)
		(width 0.12954)
		(layer "B.Cu")
		(net "FM_CPU0_PKGID2")
	)
	(segment
		(start 352.373946 -273.137376)
		(end 352.359214 -273.12874)
		(width 0.0889)
		(layer "B.Cu")
		(net "FM_CPU0_PKGID2")
	)
	(segment
		(start 356.026212 -269.38351)
		(end 356.026212 -269.405608)
		(width 0.0889)
		(layer "B.Cu")
		(net "FM_CPU0_PKGID2")
	)
	(segment
		(start 295.54932 -275.91893)
		(end 293.625778 -275.91893)
		(width 0.12954)
		(layer "B.Cu")
		(net "FM_CPU0_PKGID2")
	)
	(segment
		(start 357.045514 -268.051026)
		(end 356.707694 -268.051026)
		(width 0.0889)
		(layer "B.Cu")
		(net "FM_CPU0_PKGID2")
	)
	(segment
		(start 277.103078 -200.79335)
		(end 275.413978 -199.10425)
		(width 0.12954)
		(layer "B.Cu")
		(net "FM_CPU0_PKGID2")
	)
	(segment
		(start 302.851566 -275.645118)
		(end 299.76953 -275.645118)
		(width 0.12954)
		(layer "B.Cu")
		(net "FM_CPU0_PKGID2")
	)
	(segment
		(start 325.418958 -275.96973)
		(end 318.403478 -275.96973)
		(width 0.12954)
		(layer "B.Cu")
		(net "FM_CPU0_PKGID2")
	)
	(segment
		(start 310.631078 -277.12797)
		(end 307.677058 -277.12797)
		(width 0.12954)
		(layer "B.Cu")
		(net "FM_CPU0_PKGID2")
	)
	(segment
		(start 356.381304 -268.377416)
		(end 356.381304 -268.911324)
		(width 0.0889)
		(layer "B.Cu")
		(net "FM_CPU0_PKGID2")
	)
	(segment
		(start 333.704184 -274.170902)
		(end 333.158846 -274.71624)
		(width 0.12954)
		(layer "B.Cu")
		(net "FM_CPU0_PKGID2")
	)
	(segment
		(start 277.103078 -253.951232)
		(end 277.103078 -200.79335)
		(width 0.12954)
		(layer "B.Cu")
		(net "FM_CPU0_PKGID2")
	)
	(segment
		(start 292.645338 -274.93849)
		(end 290.562538 -274.93849)
		(width 0.12954)
		(layer "B.Cu")
		(net "FM_CPU0_PKGID2")
	)
	(segment
		(start 200.52792 -149.885908)
		(end 200.58888 -149.824948)
		(width 0.12954)
		(layer "B.Cu")
		(net "FM_CPU0_PKGID2")
	)
	(segment
		(start 350.574864 -273.942556)
		(end 350.560132 -273.951192)
		(width 0.0889)
		(layer "B.Cu")
		(net "FM_CPU0_PKGID2")
	)
	(segment
		(start 343.996264 -273.942556)
		(end 343.981532 -273.951192)
		(width 0.0889)
		(layer "B.Cu")
		(net "FM_CPU0_PKGID2")
	)
	(segment
		(start 333.158846 -274.71624)
		(end 326.672448 -274.71624)
		(width 0.12954)
		(layer "B.Cu")
		(net "FM_CPU0_PKGID2")
	)
	(segment
		(start 354.146612 -272.639282)
		(end 354.146612 -272.654776)
		(width 0.0889)
		(layer "B.Cu")
		(net "FM_CPU0_PKGID2")
	)
	(segment
		(start 316.269878 -276.35327)
		(end 311.405778 -276.35327)
		(width 0.12954)
		(layer "B.Cu")
		(net "FM_CPU0_PKGID2")
	)
	(segment
		(start 341.176864 -273.942556)
		(end 341.162132 -273.951192)
		(width 0.0889)
		(layer "B.Cu")
		(net "FM_CPU0_PKGID2")
	)
	(segment
		(start 354.616766 -271.825212)
		(end 354.616766 -271.839436)
		(width 0.0889)
		(layer "B.Cu")
		(net "FM_CPU0_PKGID2")
	)
	(segment
		(start 287.778698 -271.24279)
		(end 287.423098 -271.24279)
		(width 0.12954)
		(layer "B.Cu")
		(net "FM_CPU0_PKGID2")
	)
	(segment
		(start 286.666178 -270.48587)
		(end 286.666178 -266.419584)
		(width 0.12954)
		(layer "B.Cu")
		(net "FM_CPU0_PKGID2")
	)
	(segment
		(start 316.653418 -275.96973)
		(end 316.269878 -276.35327)
		(width 0.12954)
		(layer "B.Cu")
		(net "FM_CPU0_PKGID2")
	)
	(segment
		(start 286.666178 -266.419584)
		(end 286.467804 -266.22121)
		(width 0.12954)
		(layer "B.Cu")
		(net "FM_CPU0_PKGID2")
	)
	(segment
		(start 340.237064 -273.942556)
		(end 340.22665 -273.948652)
		(width 0.0889)
		(layer "B.Cu")
		(net "FM_CPU0_PKGID2")
	)
	(segment
		(start 356.707694 -268.051026)
		(end 356.381304 -268.377416)
		(width 0.0889)
		(layer "B.Cu")
		(net "FM_CPU0_PKGID2")
	)
	(segment
		(start 346.815664 -273.942556)
		(end 346.800932 -273.951192)
		(width 0.0889)
		(layer "B.Cu")
		(net "FM_CPU0_PKGID2")
	)
	(segment
		(start 318.403478 -275.96973)
		(end 316.653418 -275.96973)
		(width 0.12954)
		(layer "B.Cu")
		(net "FM_CPU0_PKGID2")
	)
	(segment
		(start 334.35163 -274.170902)
		(end 333.822294 -274.170902)
		(width 0.0889)
		(layer "B.Cu")
		(net "FM_CPU0_PKGID2")
	)
	(segment
		(start 239.146842 -158.025338)
		(end 205.905354 -158.025338)
		(width 0.12954)
		(layer "B.Cu")
		(net "FM_CPU0_PKGID2")
	)
	(segment
		(start 286.467804 -258.099306)
		(end 284.56763 -256.199132)
		(width 0.12954)
		(layer "B.Cu")
		(net "FM_CPU0_PKGID2")
	)
	(segment
		(start 303.928018 -276.72157)
		(end 302.851566 -275.645118)
		(width 0.12954)
		(layer "B.Cu")
		(net "FM_CPU0_PKGID2")
	)
	(segment
		(start 293.625778 -275.91893)
		(end 292.645338 -274.93849)
		(width 0.12954)
		(layer "B.Cu")
		(net "FM_CPU0_PKGID2")
	)
	(segment
		(start 354.334064 -272.314924)
		(end 354.325174 -272.320004)
		(width 0.0889)
		(layer "B.Cu")
		(net "FM_CPU0_PKGID2")
	)
	(segment
		(start 356.21976 -269.055596)
		(end 356.213664 -269.059152)
		(width 0.0889)
		(layer "B.Cu")
		(net "FM_CPU0_PKGID2")
	)
	(segment
		(start 286.467804 -266.22121)
		(end 286.467804 -258.099306)
		(width 0.12954)
		(layer "B.Cu")
		(net "FM_CPU0_PKGID2")
	)
	(segment
		(start 200.52792 -152.647904)
		(end 200.52792 -149.885908)
		(width 0.12954)
		(layer "B.Cu")
		(net "FM_CPU0_PKGID2")
	)
	(segment
		(start 274.470114 -199.10425)
		(end 273.127978 -197.762114)
		(width 0.12954)
		(layer "B.Cu")
		(net "FM_CPU0_PKGID2")
	)
	(segment
		(start 275.413978 -199.10425)
		(end 274.470114 -199.10425)
		(width 0.12954)
		(layer "B.Cu")
		(net "FM_CPU0_PKGID2")
	)
	(segment
		(start 298.250356 -275.96719)
		(end 298.113196 -276.10435)
		(width 0.12954)
		(layer "B.Cu")
		(net "FM_CPU0_PKGID2")
	)
	(segment
		(start 355.27996 -270.683482)
		(end 355.273864 -270.687038)
		(width 0.0889)
		(layer "B.Cu")
		(net "FM_CPU0_PKGID2")
	)
	(segment
		(start 307.677058 -277.12797)
		(end 307.270658 -276.72157)
		(width 0.12954)
		(layer "B.Cu")
		(net "FM_CPU0_PKGID2")
	)
	(segment
		(start 290.562538 -274.93849)
		(end 288.614358 -272.99031)
		(width 0.12954)
		(layer "B.Cu")
		(net "FM_CPU0_PKGID2")
	)
	(segment
		(start 333.822294 -274.170902)
		(end 333.704184 -274.170902)
		(width 0.12954)
		(layer "B.Cu")
		(net "FM_CPU0_PKGID2")
	)
	(segment
		(start 326.672448 -274.71624)
		(end 325.418958 -275.96973)
		(width 0.12954)
		(layer "B.Cu")
		(net "FM_CPU0_PKGID2")
	)
	(segment
		(start 299.76953 -275.645118)
		(end 299.447458 -275.96719)
		(width 0.12954)
		(layer "B.Cu")
		(net "FM_CPU0_PKGID2")
	)
	(segment
		(start 355.086412 -271.011396)
		(end 355.086412 -271.02689)
		(width 0.0889)
		(layer "B.Cu")
		(net "FM_CPU0_PKGID2")
	)
	(segment
		(start 295.73474 -276.10435)
		(end 295.54932 -275.91893)
		(width 0.12954)
		(layer "B.Cu")
		(net "FM_CPU0_PKGID2")
	)
	(segment
		(start 288.614358 -272.99031)
		(end 288.614358 -272.07845)
		(width 0.12954)
		(layer "B.Cu")
		(net "FM_CPU0_PKGID2")
	)
	(segment
		(start 344.936064 -273.942556)
		(end 344.921332 -273.951192)
		(width 0.0889)
		(layer "B.Cu")
		(net "FM_CPU0_PKGID2")
	)
	(segment
		(start 307.270658 -276.72157)
		(end 303.928018 -276.72157)
		(width 0.12954)
		(layer "B.Cu")
		(net "FM_CPU0_PKGID2")
	)
	(segment
		(start 350.857566 -273.444462)
		(end 350.857566 -273.453098)
		(width 0.0889)
		(layer "B.Cu")
		(net "FM_CPU0_PKGID2")
	)
	(segment
		(start 334.52054 -274.001992)
		(end 334.35163 -274.170902)
		(width 0.0889)
		(layer "B.Cu")
		(net "FM_CPU0_PKGID2")
	)
	(segment
		(start 356.213664 -269.059152)
		(end 356.204774 -269.064232)
		(width 0.0889)
		(layer "B.Cu")
		(net "FM_CPU0_PKGID2")
	)
	(segment
		(start 284.56763 -256.199132)
		(end 279.350978 -256.199132)
		(width 0.12954)
		(layer "B.Cu")
		(net "FM_CPU0_PKGID2")
	)
	(segment
		(start 279.350978 -256.199132)
		(end 277.103078 -253.951232)
		(width 0.12954)
		(layer "B.Cu")
		(net "FM_CPU0_PKGID2")
	)
	(segment
		(start 342.116664 -273.942556)
		(end 342.101932 -273.951192)
		(width 0.0889)
		(layer "B.Cu")
		(net "FM_CPU0_PKGID2")
	)
	(segment
		(start 205.905354 -158.025338)
		(end 200.52792 -152.647904)
		(width 0.12954)
		(layer "B.Cu")
		(net "FM_CPU0_PKGID2")
	)
	(segment
		(start 355.744018 -269.873222)
		(end 355.735128 -269.878302)
		(width 0.0889)
		(layer "B.Cu")
		(net "FM_CPU0_PKGID2")
	)
	(segment
		(start 354.804218 -271.500854)
		(end 354.795328 -271.505934)
		(width 0.0889)
		(layer "B.Cu")
		(net "FM_CPU0_PKGID2")
	)
	(segment
		(start 347.755464 -273.942556)
		(end 347.740732 -273.951192)
		(width 0.0889)
		(layer "B.Cu")
		(net "FM_CPU0_PKGID2")
	)
	(segment
		(start 273.127978 -197.762114)
		(end 273.127978 -192.006474)
		(width 0.12954)
		(layer "B.Cu")
		(net "FM_CPU0_PKGID2")
	)
	(segment
		(start 348.695264 -273.942556)
		(end 348.680532 -273.951192)
		(width 0.0889)
		(layer "B.Cu")
		(net "FM_CPU0_PKGID2")
	)
	(arc
		(start 345.31046 -273.942556)
		(mid 345.123262 -273.892413)
		(end 344.936064 -273.942556)
		(width 0.0889)
		(layer "B.Cu")
		(net "FM_CPU0_PKGID2")
	)
	(arc
		(start 338.357464 -273.942556)
		(mid 338.074762 -274.018332)
		(end 337.79206 -273.942556)
		(width 0.0889)
		(layer "B.Cu")
		(net "FM_CPU0_PKGID2")
	)
	(arc
		(start 353.299014 -273.12874)
		(mid 353.111816 -273.078597)
		(end 352.924618 -273.12874)
		(width 0.0889)
		(layer "B.Cu")
		(net "FM_CPU0_PKGID2")
	)
	(arc
		(start 343.981532 -273.951192)
		(mid 343.705057 -274.018512)
		(end 343.43086 -273.942556)
		(width 0.0889)
		(layer "B.Cu")
		(net "FM_CPU0_PKGID2")
	)
	(arc
		(start 341.55126 -273.942556)
		(mid 341.364062 -273.892413)
		(end 341.176864 -273.942556)
		(width 0.0889)
		(layer "B.Cu")
		(net "FM_CPU0_PKGID2")
	)
	(arc
		(start 353.864418 -273.12874)
		(mid 353.590219 -273.204575)
		(end 353.313746 -273.137376)
		(width 0.0889)
		(layer "B.Cu")
		(net "FM_CPU0_PKGID2")
	)
	(arc
		(start 354.325174 -272.320004)
		(mid 354.19426 -272.456364)
		(end 354.146612 -272.639282)
		(width 0.0889)
		(layer "B.Cu")
		(net "FM_CPU0_PKGID2")
	)
	(arc
		(start 350.857566 -273.453098)
		(mid 350.783575 -273.732664)
		(end 350.58096 -273.939)
		(width 0.0889)
		(layer "B.Cu")
		(net "FM_CPU0_PKGID2")
	)
	(arc
		(start 347.19006 -273.942556)
		(mid 347.002862 -273.892413)
		(end 346.815664 -273.942556)
		(width 0.0889)
		(layer "B.Cu")
		(net "FM_CPU0_PKGID2")
	)
	(arc
		(start 346.25026 -273.942556)
		(mid 346.063062 -273.892413)
		(end 345.875864 -273.942556)
		(width 0.0889)
		(layer "B.Cu")
		(net "FM_CPU0_PKGID2")
	)
	(arc
		(start 354.616766 -271.839436)
		(mid 354.537547 -272.114121)
		(end 354.334064 -272.314924)
		(width 0.0889)
		(layer "B.Cu")
		(net "FM_CPU0_PKGID2")
	)
	(arc
		(start 346.800932 -273.951192)
		(mid 346.524457 -274.018512)
		(end 346.25026 -273.942556)
		(width 0.0889)
		(layer "B.Cu")
		(net "FM_CPU0_PKGID2")
	)
	(arc
		(start 354.146612 -272.654776)
		(mid 354.067242 -272.92851)
		(end 353.864418 -273.12874)
		(width 0.0889)
		(layer "B.Cu")
		(net "FM_CPU0_PKGID2")
	)
	(arc
		(start 336.85226 -273.942556)
		(mid 336.665062 -273.892413)
		(end 336.477864 -273.942556)
		(width 0.0889)
		(layer "B.Cu")
		(net "FM_CPU0_PKGID2")
	)
	(arc
		(start 352.359214 -273.12874)
		(mid 352.172016 -273.078597)
		(end 351.984818 -273.12874)
		(width 0.0889)
		(layer "B.Cu")
		(net "FM_CPU0_PKGID2")
	)
	(arc
		(start 338.73186 -273.942556)
		(mid 338.544662 -273.892413)
		(end 338.357464 -273.942556)
		(width 0.0889)
		(layer "B.Cu")
		(net "FM_CPU0_PKGID2")
	)
	(arc
		(start 339.287104 -273.948652)
		(mid 339.008672 -274.018498)
		(end 338.73186 -273.942556)
		(width 0.0889)
		(layer "B.Cu")
		(net "FM_CPU0_PKGID2")
	)
	(arc
		(start 349.06966 -273.942556)
		(mid 348.882462 -273.892413)
		(end 348.695264 -273.942556)
		(width 0.0889)
		(layer "B.Cu")
		(net "FM_CPU0_PKGID2")
	)
	(arc
		(start 337.79206 -273.942556)
		(mid 337.604862 -273.892413)
		(end 337.417664 -273.942556)
		(width 0.0889)
		(layer "B.Cu")
		(net "FM_CPU0_PKGID2")
	)
	(arc
		(start 343.43086 -273.942556)
		(mid 343.243662 -273.892413)
		(end 343.056464 -273.942556)
		(width 0.0889)
		(layer "B.Cu")
		(net "FM_CPU0_PKGID2")
	)
	(arc
		(start 344.921332 -273.951192)
		(mid 344.644857 -274.018512)
		(end 344.37066 -273.942556)
		(width 0.0889)
		(layer "B.Cu")
		(net "FM_CPU0_PKGID2")
	)
	(arc
		(start 345.861132 -273.951192)
		(mid 345.584657 -274.018512)
		(end 345.31046 -273.942556)
		(width 0.0889)
		(layer "B.Cu")
		(net "FM_CPU0_PKGID2")
	)
	(arc
		(start 350.00946 -273.942556)
		(mid 349.822262 -273.892413)
		(end 349.635064 -273.942556)
		(width 0.0889)
		(layer "B.Cu")
		(net "FM_CPU0_PKGID2")
	)
	(arc
		(start 347.740732 -273.951192)
		(mid 347.464257 -274.018512)
		(end 347.19006 -273.942556)
		(width 0.0889)
		(layer "B.Cu")
		(net "FM_CPU0_PKGID2")
	)
	(arc
		(start 335.91246 -273.942556)
		(mid 335.725262 -273.892413)
		(end 335.538064 -273.942556)
		(width 0.0889)
		(layer "B.Cu")
		(net "FM_CPU0_PKGID2")
	)
	(arc
		(start 349.635064 -273.942556)
		(mid 349.352362 -274.018332)
		(end 349.06966 -273.942556)
		(width 0.0889)
		(layer "B.Cu")
		(net "FM_CPU0_PKGID2")
	)
	(arc
		(start 335.538064 -273.942556)
		(mid 335.255362 -274.018332)
		(end 334.97266 -273.942556)
		(width 0.0889)
		(layer "B.Cu")
		(net "FM_CPU0_PKGID2")
	)
	(arc
		(start 350.560132 -273.951192)
		(mid 350.283657 -274.018512)
		(end 350.00946 -273.942556)
		(width 0.0889)
		(layer "B.Cu")
		(net "FM_CPU0_PKGID2")
	)
	(arc
		(start 352.924618 -273.12874)
		(mid 352.650419 -273.204575)
		(end 352.373946 -273.137376)
		(width 0.0889)
		(layer "B.Cu")
		(net "FM_CPU0_PKGID2")
	)
	(arc
		(start 351.984818 -273.12874)
		(mid 351.708005 -273.20461)
		(end 351.429574 -273.134836)
		(width 0.0889)
		(layer "B.Cu")
		(net "FM_CPU0_PKGID2")
	)
	(arc
		(start 342.49106 -273.942556)
		(mid 342.303862 -273.892413)
		(end 342.116664 -273.942556)
		(width 0.0889)
		(layer "B.Cu")
		(net "FM_CPU0_PKGID2")
	)
	(arc
		(start 348.12986 -273.942556)
		(mid 347.942662 -273.892413)
		(end 347.755464 -273.942556)
		(width 0.0889)
		(layer "B.Cu")
		(net "FM_CPU0_PKGID2")
	)
	(arc
		(start 334.97266 -273.942556)
		(mid 334.785462 -273.892413)
		(end 334.598264 -273.942556)
		(width 0.0889)
		(layer "B.Cu")
		(net "FM_CPU0_PKGID2")
	)
	(arc
		(start 356.026212 -269.405608)
		(mid 355.945301 -269.675736)
		(end 355.744018 -269.873222)
		(width 0.0889)
		(layer "B.Cu")
		(net "FM_CPU0_PKGID2")
	)
	(arc
		(start 354.795328 -271.505934)
		(mid 354.664414 -271.642294)
		(end 354.616766 -271.825212)
		(width 0.0889)
		(layer "B.Cu")
		(net "FM_CPU0_PKGID2")
	)
	(arc
		(start 343.056464 -273.942556)
		(mid 342.773762 -274.018332)
		(end 342.49106 -273.942556)
		(width 0.0889)
		(layer "B.Cu")
		(net "FM_CPU0_PKGID2")
	)
	(arc
		(start 351.044764 -273.12874)
		(mid 350.909831 -273.262094)
		(end 350.857566 -273.444462)
		(width 0.0889)
		(layer "B.Cu")
		(net "FM_CPU0_PKGID2")
	)
	(arc
		(start 341.162132 -273.951192)
		(mid 340.885657 -274.018512)
		(end 340.61146 -273.942556)
		(width 0.0889)
		(layer "B.Cu")
		(net "FM_CPU0_PKGID2")
	)
	(arc
		(start 355.556566 -270.19758)
		(mid 355.482575 -270.477146)
		(end 355.27996 -270.683482)
		(width 0.0889)
		(layer "B.Cu")
		(net "FM_CPU0_PKGID2")
	)
	(arc
		(start 355.086412 -271.02689)
		(mid 355.007042 -271.300624)
		(end 354.804218 -271.500854)
		(width 0.0889)
		(layer "B.Cu")
		(net "FM_CPU0_PKGID2")
	)
	(arc
		(start 340.22665 -273.948652)
		(mid 339.948472 -274.018375)
		(end 339.671914 -273.942556)
		(width 0.0889)
		(layer "B.Cu")
		(net "FM_CPU0_PKGID2")
	)
	(arc
		(start 351.41916 -273.12874)
		(mid 351.231962 -273.078597)
		(end 351.044764 -273.12874)
		(width 0.0889)
		(layer "B.Cu")
		(net "FM_CPU0_PKGID2")
	)
	(arc
		(start 342.101932 -273.951192)
		(mid 341.825457 -274.018512)
		(end 341.55126 -273.942556)
		(width 0.0889)
		(layer "B.Cu")
		(net "FM_CPU0_PKGID2")
	)
	(arc
		(start 355.735128 -269.878302)
		(mid 355.604214 -270.014662)
		(end 355.556566 -270.19758)
		(width 0.0889)
		(layer "B.Cu")
		(net "FM_CPU0_PKGID2")
	)
	(arc
		(start 348.680532 -273.951192)
		(mid 348.404057 -274.018512)
		(end 348.12986 -273.942556)
		(width 0.0889)
		(layer "B.Cu")
		(net "FM_CPU0_PKGID2")
	)
	(arc
		(start 336.477864 -273.942556)
		(mid 336.195162 -274.018332)
		(end 335.91246 -273.942556)
		(width 0.0889)
		(layer "B.Cu")
		(net "FM_CPU0_PKGID2")
	)
	(arc
		(start 344.37066 -273.942556)
		(mid 344.183462 -273.892413)
		(end 343.996264 -273.942556)
		(width 0.0889)
		(layer "B.Cu")
		(net "FM_CPU0_PKGID2")
	)
	(arc
		(start 356.381304 -268.911324)
		(mid 356.307512 -268.991277)
		(end 356.21976 -269.055596)
		(width 0.0889)
		(layer "B.Cu")
		(net "FM_CPU0_PKGID2")
	)
	(arc
		(start 339.671914 -273.942556)
		(mid 339.484716 -273.892413)
		(end 339.297518 -273.942556)
		(width 0.0889)
		(layer "B.Cu")
		(net "FM_CPU0_PKGID2")
	)
	(arc
		(start 337.417664 -273.942556)
		(mid 337.134962 -274.018332)
		(end 336.85226 -273.942556)
		(width 0.0889)
		(layer "B.Cu")
		(net "FM_CPU0_PKGID2")
	)
	(arc
		(start 334.598264 -273.942556)
		(mid 334.557455 -273.969728)
		(end 334.52054 -274.001992)
		(width 0.0889)
		(layer "B.Cu")
		(net "FM_CPU0_PKGID2")
	)
	(arc
		(start 356.204774 -269.064232)
		(mid 356.07386 -269.200592)
		(end 356.026212 -269.38351)
		(width 0.0889)
		(layer "B.Cu")
		(net "FM_CPU0_PKGID2")
	)
	(arc
		(start 355.264974 -270.692118)
		(mid 355.13406 -270.828478)
		(end 355.086412 -271.011396)
		(width 0.0889)
		(layer "B.Cu")
		(net "FM_CPU0_PKGID2")
	)
	(arc
		(start 340.61146 -273.942556)
		(mid 340.424262 -273.892413)
		(end 340.237064 -273.942556)
		(width 0.0889)
		(layer "B.Cu")
		(net "FM_CPU0_PKGID2")
	)
	(segment
		(start 200.111868 -149.824948)
		(end 198.801482 -149.28215)
		(width 0.127)
		(layer "In2.Cu")
		(net "FM_CPU0_PKGID2")
	)
	(segment
		(start 196.57568 -147.056348)
		(end 189.558168 -147.056348)
		(width 0.127)
		(layer "In2.Cu")
		(net "FM_CPU0_PKGID2")
	)
	(segment
		(start 189.558168 -147.056348)
		(end 183.67248 -141.17066)
		(width 0.127)
		(layer "In2.Cu")
		(net "FM_CPU0_PKGID2")
	)
	(segment
		(start 200.58888 -149.824948)
		(end 200.111868 -149.824948)
		(width 0.127)
		(layer "In2.Cu")
		(net "FM_CPU0_PKGID2")
	)
	(segment
		(start 198.801482 -149.28215)
		(end 196.57568 -147.056348)
		(width 0.127)
		(layer "In2.Cu")
		(net "FM_CPU0_PKGID2")
	)
	(segment
		(start 183.67248 -141.17066)
		(end 183.67248 -133.441948)
		(width 0.127)
		(layer "In2.Cu")
		(net "FM_CPU0_PKGID2")
	)
	(segment
		(start 351.231962 -266.405868)
		(end 351.231962 -266.941554)
		(width 0.12954)
		(layer "F.Cu")
		(net "FM_CPU0_PKGID1")
	)
	(segment
		(start 182.17388 -129.866898)
		(end 182.17388 -129.256028)
		(width 0.12954)
		(layer "F.Cu")
		(net "FM_CPU0_PKGID1")
	)
	(segment
		(start 351.231962 -266.941554)
		(end 351.232216 -266.941808)
		(width 0.12954)
		(layer "F.Cu")
		(net "FM_CPU0_PKGID1")
	)
	(segment
		(start 179.755546 -119.375428)
		(end 180.155596 -119.775478)
		(width 0.12954)
		(layer "F.Cu")
		(net "FM_CPU0_PKGID1")
	)
	(via
		(at 321.937634 -269.357856)
		(size 0.6604)
		(drill 0.3302)
		(layers "F.Cu" "B.Cu")
		(net "FM_CPU0_PKGID1")
	)
	(via
		(at 201.60488 -151.348948)
		(size 0.508)
		(drill 0.254)
		(layers "F.Cu" "B.Cu")
		(net "FM_CPU0_PKGID1")
	)
	(via
		(at 351.232216 -266.941808)
		(size 0.4572)
		(drill 0.2032)
		(layers "F.Cu" "B.Cu")
		(net "FM_CPU0_PKGID1")
	)
	(via
		(at 182.17388 -129.256028)
		(size 0.508)
		(drill 0.254)
		(layers "F.Cu" "B.Cu")
		(net "FM_CPU0_PKGID1")
	)
	(via
		(at 180.155596 -119.775478)
		(size 0.4572)
		(drill 0.254)
		(layers "F.Cu" "B.Cu")
		(net "FM_CPU0_PKGID1")
	)
	(segment
		(start 293.592504 -262.77062)
		(end 292.428168 -262.77062)
		(width 0.12954)
		(layer "B.Cu")
		(net "FM_CPU0_PKGID1")
	)
	(segment
		(start 345.790774 -267.26007)
		(end 345.78036 -267.266166)
		(width 0.0889)
		(layer "B.Cu")
		(net "FM_CPU0_PKGID1")
	)
	(segment
		(start 284.583378 -196.34581)
		(end 284.255718 -196.01815)
		(width 0.12954)
		(layer "B.Cu")
		(net "FM_CPU0_PKGID1")
	)
	(segment
		(start 201.60488 -152.639776)
		(end 201.60488 -151.348948)
		(width 0.12954)
		(layer "B.Cu")
		(net "FM_CPU0_PKGID1")
	)
	(segment
		(start 311.527698 -270.08201)
		(end 310.730138 -270.87957)
		(width 0.12954)
		(layer "B.Cu")
		(net "FM_CPU0_PKGID1")
	)
	(segment
		(start 342.036146 -267.25753)
		(end 342.021414 -267.266166)
		(width 0.0889)
		(layer "B.Cu")
		(net "FM_CPU0_PKGID1")
	)
	(segment
		(start 282.828238 -192.51803)
		(end 283.467048 -191.87922)
		(width 0.12954)
		(layer "B.Cu")
		(net "FM_CPU0_PKGID1")
	)
	(segment
		(start 333.062072 -266.801092)
		(end 332.87081 -266.801092)
		(width 0.12954)
		(layer "B.Cu")
		(net "FM_CPU0_PKGID1")
	)
	(segment
		(start 345.405964 -267.266166)
		(end 345.39555 -267.26007)
		(width 0.0889)
		(layer "B.Cu")
		(net "FM_CPU0_PKGID1")
	)
	(segment
		(start 285.723838 -223.51111)
		(end 284.583378 -222.37065)
		(width 0.12954)
		(layer "B.Cu")
		(net "FM_CPU0_PKGID1")
	)
	(segment
		(start 302.071278 -269.22349)
		(end 301.062898 -268.21511)
		(width 0.12954)
		(layer "B.Cu")
		(net "FM_CPU0_PKGID1")
	)
	(segment
		(start 299.688758 -267.41501)
		(end 298.159678 -267.41501)
		(width 0.12954)
		(layer "B.Cu")
		(net "FM_CPU0_PKGID1")
	)
	(segment
		(start 296.970958 -265.06043)
		(end 296.259758 -265.06043)
		(width 0.12954)
		(layer "B.Cu")
		(net "FM_CPU0_PKGID1")
	)
	(segment
		(start 350.105218 -267.266166)
		(end 350.076262 -267.249402)
		(width 0.0889)
		(layer "B.Cu")
		(net "FM_CPU0_PKGID1")
	)
	(segment
		(start 292.050978 -262.39343)
		(end 292.050978 -258.45389)
		(width 0.12954)
		(layer "B.Cu")
		(net "FM_CPU0_PKGID1")
	)
	(segment
		(start 287.214818 -253.02337)
		(end 285.723838 -251.53239)
		(width 0.12954)
		(layer "B.Cu")
		(net "FM_CPU0_PKGID1")
	)
	(segment
		(start 297.303698 -265.39317)
		(end 296.970958 -265.06043)
		(width 0.12954)
		(layer "B.Cu")
		(net "FM_CPU0_PKGID1")
	)
	(segment
		(start 339.212174 -267.26007)
		(end 339.20176 -267.266166)
		(width 0.0889)
		(layer "B.Cu")
		(net "FM_CPU0_PKGID1")
	)
	(segment
		(start 310.730138 -270.87957)
		(end 307.405278 -270.87957)
		(width 0.12954)
		(layer "B.Cu")
		(net "FM_CPU0_PKGID1")
	)
	(segment
		(start 315.490352 -269.357856)
		(end 314.766198 -270.08201)
		(width 0.12954)
		(layer "B.Cu")
		(net "FM_CPU0_PKGID1")
	)
	(segment
		(start 296.259758 -265.06043)
		(end 296.041318 -264.84199)
		(width 0.12954)
		(layer "B.Cu")
		(net "FM_CPU0_PKGID1")
	)
	(segment
		(start 343.915746 -267.25753)
		(end 343.901014 -267.266166)
		(width 0.0889)
		(layer "B.Cu")
		(net "FM_CPU0_PKGID1")
	)
	(segment
		(start 351.232216 -266.941808)
		(end 350.610932 -267.210794)
		(width 0.0889)
		(layer "B.Cu")
		(net "FM_CPU0_PKGID1")
	)
	(segment
		(start 289.919918 -253.74981)
		(end 289.193478 -253.02337)
		(width 0.12954)
		(layer "B.Cu")
		(net "FM_CPU0_PKGID1")
	)
	(segment
		(start 298.159678 -267.41501)
		(end 297.303698 -266.55903)
		(width 0.12954)
		(layer "B.Cu")
		(net "FM_CPU0_PKGID1")
	)
	(segment
		(start 282.828238 -195.190618)
		(end 282.828238 -192.51803)
		(width 0.12954)
		(layer "B.Cu")
		(net "FM_CPU0_PKGID1")
	)
	(segment
		(start 301.062898 -268.21511)
		(end 300.488858 -268.21511)
		(width 0.12954)
		(layer "B.Cu")
		(net "FM_CPU0_PKGID1")
	)
	(segment
		(start 304.009298 -270.05661)
		(end 303.176178 -269.22349)
		(width 0.12954)
		(layer "B.Cu")
		(net "FM_CPU0_PKGID1")
	)
	(segment
		(start 300.488858 -268.21511)
		(end 299.688758 -267.41501)
		(width 0.12954)
		(layer "B.Cu")
		(net "FM_CPU0_PKGID1")
	)
	(segment
		(start 341.096346 -267.25753)
		(end 341.081614 -267.266166)
		(width 0.0889)
		(layer "B.Cu")
		(net "FM_CPU0_PKGID1")
	)
	(segment
		(start 349.554546 -267.25753)
		(end 349.539814 -267.266166)
		(width 0.0889)
		(layer "B.Cu")
		(net "FM_CPU0_PKGID1")
	)
	(segment
		(start 297.303698 -266.55903)
		(end 297.303698 -265.39317)
		(width 0.12954)
		(layer "B.Cu")
		(net "FM_CPU0_PKGID1")
	)
	(segment
		(start 334.989932 -267.316966)
		(end 334.474058 -266.801092)
		(width 0.0889)
		(layer "B.Cu")
		(net "FM_CPU0_PKGID1")
	)
	(segment
		(start 283.65577 -196.01815)
		(end 282.828238 -195.190618)
		(width 0.12954)
		(layer "B.Cu")
		(net "FM_CPU0_PKGID1")
	)
	(segment
		(start 303.176178 -269.22349)
		(end 302.071278 -269.22349)
		(width 0.12954)
		(layer "B.Cu")
		(net "FM_CPU0_PKGID1")
	)
	(segment
		(start 314.766198 -270.08201)
		(end 311.527698 -270.08201)
		(width 0.12954)
		(layer "B.Cu")
		(net "FM_CPU0_PKGID1")
	)
	(segment
		(start 283.467048 -191.87922)
		(end 283.467048 -188.6331)
		(width 0.12954)
		(layer "B.Cu")
		(net "FM_CPU0_PKGID1")
	)
	(segment
		(start 330.76007 -268.911832)
		(end 322.383658 -268.911832)
		(width 0.12954)
		(layer "B.Cu")
		(net "FM_CPU0_PKGID1")
	)
	(segment
		(start 295.685718 -263.16559)
		(end 293.987474 -263.16559)
		(width 0.12954)
		(layer "B.Cu")
		(net "FM_CPU0_PKGID1")
	)
	(segment
		(start 342.975946 -267.25753)
		(end 342.961214 -267.266166)
		(width 0.0889)
		(layer "B.Cu")
		(net "FM_CPU0_PKGID1")
	)
	(segment
		(start 282.807918 -187.97397)
		(end 270.180562 -187.97397)
		(width 0.12954)
		(layer "B.Cu")
		(net "FM_CPU0_PKGID1")
	)
	(segment
		(start 321.937634 -269.357856)
		(end 315.490352 -269.357856)
		(width 0.12954)
		(layer "B.Cu")
		(net "FM_CPU0_PKGID1")
	)
	(segment
		(start 340.156546 -267.25753)
		(end 340.141814 -267.266166)
		(width 0.0889)
		(layer "B.Cu")
		(net "FM_CPU0_PKGID1")
	)
	(segment
		(start 206.218282 -157.253178)
		(end 201.60488 -152.639776)
		(width 0.12954)
		(layer "B.Cu")
		(net "FM_CPU0_PKGID1")
	)
	(segment
		(start 334.474058 -266.801092)
		(end 333.062072 -266.801092)
		(width 0.0889)
		(layer "B.Cu")
		(net "FM_CPU0_PKGID1")
	)
	(segment
		(start 346.735146 -267.25753)
		(end 346.720414 -267.266166)
		(width 0.0889)
		(layer "B.Cu")
		(net "FM_CPU0_PKGID1")
	)
	(segment
		(start 284.255718 -196.01815)
		(end 283.65577 -196.01815)
		(width 0.12954)
		(layer "B.Cu")
		(net "FM_CPU0_PKGID1")
	)
	(segment
		(start 296.041318 -264.84199)
		(end 296.041318 -263.52119)
		(width 0.12954)
		(layer "B.Cu")
		(net "FM_CPU0_PKGID1")
	)
	(segment
		(start 284.583378 -222.37065)
		(end 284.583378 -196.34581)
		(width 0.12954)
		(layer "B.Cu")
		(net "FM_CPU0_PKGID1")
	)
	(segment
		(start 338.827364 -267.266166)
		(end 338.812632 -267.25753)
		(width 0.0889)
		(layer "B.Cu")
		(net "FM_CPU0_PKGID1")
	)
	(segment
		(start 289.193478 -253.02337)
		(end 287.214818 -253.02337)
		(width 0.12954)
		(layer "B.Cu")
		(net "FM_CPU0_PKGID1")
	)
	(segment
		(start 292.428168 -262.77062)
		(end 292.050978 -262.39343)
		(width 0.12954)
		(layer "B.Cu")
		(net "FM_CPU0_PKGID1")
	)
	(segment
		(start 289.919918 -256.32283)
		(end 289.919918 -253.74981)
		(width 0.12954)
		(layer "B.Cu")
		(net "FM_CPU0_PKGID1")
	)
	(segment
		(start 332.87081 -266.801092)
		(end 330.76007 -268.911832)
		(width 0.12954)
		(layer "B.Cu")
		(net "FM_CPU0_PKGID1")
	)
	(segment
		(start 292.050978 -258.45389)
		(end 289.919918 -256.32283)
		(width 0.12954)
		(layer "B.Cu")
		(net "FM_CPU0_PKGID1")
	)
	(segment
		(start 306.582318 -270.05661)
		(end 304.009298 -270.05661)
		(width 0.12954)
		(layer "B.Cu")
		(net "FM_CPU0_PKGID1")
	)
	(segment
		(start 296.041318 -263.52119)
		(end 295.685718 -263.16559)
		(width 0.12954)
		(layer "B.Cu")
		(net "FM_CPU0_PKGID1")
	)
	(segment
		(start 239.45977 -157.253178)
		(end 206.218282 -157.253178)
		(width 0.12954)
		(layer "B.Cu")
		(net "FM_CPU0_PKGID1")
	)
	(segment
		(start 348.614746 -267.25753)
		(end 348.600014 -267.266166)
		(width 0.0889)
		(layer "B.Cu")
		(net "FM_CPU0_PKGID1")
	)
	(segment
		(start 347.674946 -267.25753)
		(end 347.660214 -267.266166)
		(width 0.0889)
		(layer "B.Cu")
		(net "FM_CPU0_PKGID1")
	)
	(segment
		(start 283.467048 -188.6331)
		(end 282.807918 -187.97397)
		(width 0.12954)
		(layer "B.Cu")
		(net "FM_CPU0_PKGID1")
	)
	(segment
		(start 350.494346 -267.25753)
		(end 350.479614 -267.266166)
		(width 0.0889)
		(layer "B.Cu")
		(net "FM_CPU0_PKGID1")
	)
	(segment
		(start 350.076262 -267.249402)
		(end 350.046798 -267.236702)
		(width 0.0889)
		(layer "B.Cu")
		(net "FM_CPU0_PKGID1")
	)
	(segment
		(start 285.723838 -251.53239)
		(end 285.723838 -223.51111)
		(width 0.12954)
		(layer "B.Cu")
		(net "FM_CPU0_PKGID1")
	)
	(segment
		(start 322.383658 -268.911832)
		(end 321.937634 -269.357856)
		(width 0.12954)
		(layer "B.Cu")
		(net "FM_CPU0_PKGID1")
	)
	(segment
		(start 307.405278 -270.87957)
		(end 306.582318 -270.05661)
		(width 0.12954)
		(layer "B.Cu")
		(net "FM_CPU0_PKGID1")
	)
	(segment
		(start 293.987474 -263.16559)
		(end 293.592504 -262.77062)
		(width 0.12954)
		(layer "B.Cu")
		(net "FM_CPU0_PKGID1")
	)
	(segment
		(start 336.195162 -267.316966)
		(end 334.989932 -267.316966)
		(width 0.0889)
		(layer "B.Cu")
		(net "FM_CPU0_PKGID1")
	)
	(segment
		(start 270.180562 -187.97397)
		(end 239.45977 -157.253178)
		(width 0.12954)
		(layer "B.Cu")
		(net "FM_CPU0_PKGID1")
	)
	(arc
		(start 346.720414 -267.266166)
		(mid 346.533216 -267.316309)
		(end 346.346018 -267.266166)
		(width 0.0889)
		(layer "B.Cu")
		(net "FM_CPU0_PKGID1")
	)
	(arc
		(start 336.947764 -267.266166)
		(mid 336.665062 -267.190424)
		(end 336.38236 -267.266166)
		(width 0.0889)
		(layer "B.Cu")
		(net "FM_CPU0_PKGID1")
	)
	(arc
		(start 339.20176 -267.266166)
		(mid 339.014562 -267.316309)
		(end 338.827364 -267.266166)
		(width 0.0889)
		(layer "B.Cu")
		(net "FM_CPU0_PKGID1")
	)
	(arc
		(start 343.901014 -267.266166)
		(mid 343.713816 -267.316309)
		(end 343.526618 -267.266166)
		(width 0.0889)
		(layer "B.Cu")
		(net "FM_CPU0_PKGID1")
	)
	(arc
		(start 350.479614 -267.266166)
		(mid 350.292416 -267.316309)
		(end 350.105218 -267.266166)
		(width 0.0889)
		(layer "B.Cu")
		(net "FM_CPU0_PKGID1")
	)
	(arc
		(start 342.586818 -267.266166)
		(mid 342.312589 -267.190241)
		(end 342.036146 -267.25753)
		(width 0.0889)
		(layer "B.Cu")
		(net "FM_CPU0_PKGID1")
	)
	(arc
		(start 343.526618 -267.266166)
		(mid 343.252389 -267.190241)
		(end 342.975946 -267.25753)
		(width 0.0889)
		(layer "B.Cu")
		(net "FM_CPU0_PKGID1")
	)
	(arc
		(start 349.165418 -267.266166)
		(mid 348.891189 -267.190241)
		(end 348.614746 -267.25753)
		(width 0.0889)
		(layer "B.Cu")
		(net "FM_CPU0_PKGID1")
	)
	(arc
		(start 337.32216 -267.266166)
		(mid 337.134962 -267.316309)
		(end 336.947764 -267.266166)
		(width 0.0889)
		(layer "B.Cu")
		(net "FM_CPU0_PKGID1")
	)
	(arc
		(start 340.141814 -267.266166)
		(mid 339.954616 -267.316309)
		(end 339.767418 -267.266166)
		(width 0.0889)
		(layer "B.Cu")
		(net "FM_CPU0_PKGID1")
	)
	(arc
		(start 344.840814 -267.266166)
		(mid 344.653616 -267.316309)
		(end 344.466418 -267.266166)
		(width 0.0889)
		(layer "B.Cu")
		(net "FM_CPU0_PKGID1")
	)
	(arc
		(start 345.39555 -267.26007)
		(mid 345.117372 -267.190378)
		(end 344.840814 -267.266166)
		(width 0.0889)
		(layer "B.Cu")
		(net "FM_CPU0_PKGID1")
	)
	(arc
		(start 342.021414 -267.266166)
		(mid 341.834216 -267.316309)
		(end 341.647018 -267.266166)
		(width 0.0889)
		(layer "B.Cu")
		(net "FM_CPU0_PKGID1")
	)
	(arc
		(start 345.78036 -267.266166)
		(mid 345.593162 -267.316309)
		(end 345.405964 -267.266166)
		(width 0.0889)
		(layer "B.Cu")
		(net "FM_CPU0_PKGID1")
	)
	(arc
		(start 339.767418 -267.266166)
		(mid 339.490605 -267.19033)
		(end 339.212174 -267.26007)
		(width 0.0889)
		(layer "B.Cu")
		(net "FM_CPU0_PKGID1")
	)
	(arc
		(start 341.647018 -267.266166)
		(mid 341.372789 -267.190241)
		(end 341.096346 -267.25753)
		(width 0.0889)
		(layer "B.Cu")
		(net "FM_CPU0_PKGID1")
	)
	(arc
		(start 338.26196 -267.266166)
		(mid 338.074762 -267.316309)
		(end 337.887564 -267.266166)
		(width 0.0889)
		(layer "B.Cu")
		(net "FM_CPU0_PKGID1")
	)
	(arc
		(start 347.660214 -267.266166)
		(mid 347.473016 -267.316309)
		(end 347.285818 -267.266166)
		(width 0.0889)
		(layer "B.Cu")
		(net "FM_CPU0_PKGID1")
	)
	(arc
		(start 342.961214 -267.266166)
		(mid 342.774016 -267.316309)
		(end 342.586818 -267.266166)
		(width 0.0889)
		(layer "B.Cu")
		(net "FM_CPU0_PKGID1")
	)
	(arc
		(start 337.887564 -267.266166)
		(mid 337.604862 -267.190424)
		(end 337.32216 -267.266166)
		(width 0.0889)
		(layer "B.Cu")
		(net "FM_CPU0_PKGID1")
	)
	(arc
		(start 349.539814 -267.266166)
		(mid 349.352616 -267.316309)
		(end 349.165418 -267.266166)
		(width 0.0889)
		(layer "B.Cu")
		(net "FM_CPU0_PKGID1")
	)
	(arc
		(start 344.466418 -267.266166)
		(mid 344.192189 -267.190241)
		(end 343.915746 -267.25753)
		(width 0.0889)
		(layer "B.Cu")
		(net "FM_CPU0_PKGID1")
	)
	(arc
		(start 338.812632 -267.25753)
		(mid 338.536191 -267.190364)
		(end 338.26196 -267.266166)
		(width 0.0889)
		(layer "B.Cu")
		(net "FM_CPU0_PKGID1")
	)
	(arc
		(start 350.046798 -267.236702)
		(mid 349.798293 -267.190736)
		(end 349.554546 -267.25753)
		(width 0.0889)
		(layer "B.Cu")
		(net "FM_CPU0_PKGID1")
	)
	(arc
		(start 347.285818 -267.266166)
		(mid 347.011589 -267.190241)
		(end 346.735146 -267.25753)
		(width 0.0889)
		(layer "B.Cu")
		(net "FM_CPU0_PKGID1")
	)
	(arc
		(start 340.707218 -267.266166)
		(mid 340.432989 -267.190241)
		(end 340.156546 -267.25753)
		(width 0.0889)
		(layer "B.Cu")
		(net "FM_CPU0_PKGID1")
	)
	(arc
		(start 341.081614 -267.266166)
		(mid 340.894416 -267.316309)
		(end 340.707218 -267.266166)
		(width 0.0889)
		(layer "B.Cu")
		(net "FM_CPU0_PKGID1")
	)
	(arc
		(start 350.610932 -267.210794)
		(mid 350.551339 -267.230918)
		(end 350.494346 -267.25753)
		(width 0.0889)
		(layer "B.Cu")
		(net "FM_CPU0_PKGID1")
	)
	(arc
		(start 348.225618 -267.266166)
		(mid 347.951389 -267.190241)
		(end 347.674946 -267.25753)
		(width 0.0889)
		(layer "B.Cu")
		(net "FM_CPU0_PKGID1")
	)
	(arc
		(start 348.600014 -267.266166)
		(mid 348.412816 -267.316309)
		(end 348.225618 -267.266166)
		(width 0.0889)
		(layer "B.Cu")
		(net "FM_CPU0_PKGID1")
	)
	(arc
		(start 336.38236 -267.266166)
		(mid 336.292104 -267.303888)
		(end 336.195162 -267.316966)
		(width 0.0889)
		(layer "B.Cu")
		(net "FM_CPU0_PKGID1")
	)
	(arc
		(start 346.346018 -267.266166)
		(mid 346.069205 -267.19033)
		(end 345.790774 -267.26007)
		(width 0.0889)
		(layer "B.Cu")
		(net "FM_CPU0_PKGID1")
	)
	(segment
		(start 180.09362 -122.321828)
		(end 179.75326 -121.981468)
		(width 0.127)
		(layer "In2.Cu")
		(net "FM_CPU0_PKGID1")
	)
	(segment
		(start 181.2544 -139.974828)
		(end 181.2544 -130.175508)
		(width 0.127)
		(layer "In2.Cu")
		(net "FM_CPU0_PKGID1")
	)
	(segment
		(start 199.3138 -150.429468)
		(end 198.184008 -149.961346)
		(width 0.127)
		(layer "In2.Cu")
		(net "FM_CPU0_PKGID1")
	)
	(segment
		(start 198.184008 -149.961346)
		(end 196.16801 -147.945348)
		(width 0.127)
		(layer "In2.Cu")
		(net "FM_CPU0_PKGID1")
	)
	(segment
		(start 179.75326 -120.177814)
		(end 180.155596 -119.775478)
		(width 0.127)
		(layer "In2.Cu")
		(net "FM_CPU0_PKGID1")
	)
	(segment
		(start 179.75326 -121.981468)
		(end 179.75326 -120.177814)
		(width 0.127)
		(layer "In2.Cu")
		(net "FM_CPU0_PKGID1")
	)
	(segment
		(start 201.60488 -151.348948)
		(end 200.23328 -151.348948)
		(width 0.127)
		(layer "In2.Cu")
		(net "FM_CPU0_PKGID1")
	)
	(segment
		(start 181.42458 -127.315468)
		(end 180.09362 -125.984508)
		(width 0.127)
		(layer "In2.Cu")
		(net "FM_CPU0_PKGID1")
	)
	(segment
		(start 182.17388 -129.256028)
		(end 181.42458 -128.506728)
		(width 0.127)
		(layer "In2.Cu")
		(net "FM_CPU0_PKGID1")
	)
	(segment
		(start 196.16801 -147.945348)
		(end 189.22492 -147.945348)
		(width 0.127)
		(layer "In2.Cu")
		(net "FM_CPU0_PKGID1")
	)
	(segment
		(start 181.2544 -130.175508)
		(end 182.17388 -129.256028)
		(width 0.127)
		(layer "In2.Cu")
		(net "FM_CPU0_PKGID1")
	)
	(segment
		(start 181.42458 -128.506728)
		(end 181.42458 -127.315468)
		(width 0.127)
		(layer "In2.Cu")
		(net "FM_CPU0_PKGID1")
	)
	(segment
		(start 200.23328 -151.348948)
		(end 199.3138 -150.429468)
		(width 0.127)
		(layer "In2.Cu")
		(net "FM_CPU0_PKGID1")
	)
	(segment
		(start 180.09362 -125.984508)
		(end 180.09362 -122.321828)
		(width 0.127)
		(layer "In2.Cu")
		(net "FM_CPU0_PKGID1")
	)
	(segment
		(start 189.22492 -147.945348)
		(end 181.2544 -139.974828)
		(width 0.127)
		(layer "In2.Cu")
		(net "FM_CPU0_PKGID1")
	)
	(segment
		(start 356.400862 -267.220192)
		(end 356.400862 -267.755878)
		(width 0.12954)
		(layer "F.Cu")
		(net "FM_CPU0_PKGID0")
	)
	(segment
		(start 183.69788 -129.866898)
		(end 183.69788 -129.256028)
		(width 0.12954)
		(layer "F.Cu")
		(net "FM_CPU0_PKGID0")
	)
	(segment
		(start 179.755546 -120.175528)
		(end 180.155596 -120.575578)
		(width 0.12954)
		(layer "F.Cu")
		(net "FM_CPU0_PKGID0")
	)
	(segment
		(start 356.401116 -267.219938)
		(end 356.400862 -267.220192)
		(width 0.12954)
		(layer "F.Cu")
		(net "FM_CPU0_PKGID0")
	)
	(via
		(at 180.155596 -120.575578)
		(size 0.4572)
		(drill 0.254)
		(layers "F.Cu" "B.Cu")
		(net "FM_CPU0_PKGID0")
	)
	(via
		(at 201.09688 -150.840948)
		(size 0.508)
		(drill 0.254)
		(layers "F.Cu" "B.Cu")
		(net "FM_CPU0_PKGID0")
	)
	(via
		(at 321.408298 -275.16963)
		(size 0.6604)
		(drill 0.3302)
		(layers "F.Cu" "B.Cu")
		(net "FM_CPU0_PKGID0")
	)
	(via
		(at 356.400862 -267.755878)
		(size 0.4572)
		(drill 0.2032)
		(layers "F.Cu" "B.Cu")
		(net "FM_CPU0_PKGID0")
	)
	(via
		(at 183.69788 -129.256028)
		(size 0.508)
		(drill 0.254)
		(layers "F.Cu" "B.Cu")
		(net "FM_CPU0_PKGID0")
	)
	(segment
		(start 278.136858 -201.070972)
		(end 273.511518 -196.445632)
		(width 0.12954)
		(layer "B.Cu")
		(net "FM_CPU0_PKGID0")
	)
	(segment
		(start 355.187504 -270.516858)
		(end 355.178614 -270.521938)
		(width 0.0889)
		(layer "B.Cu")
		(net "FM_CPU0_PKGID0")
	)
	(segment
		(start 338.272374 -273.77136)
		(end 338.26196 -273.777456)
		(width 0.0889)
		(layer "B.Cu")
		(net "FM_CPU0_PKGID0")
	)
	(segment
		(start 350.666812 -273.443192)
		(end 350.666812 -273.461734)
		(width 0.0889)
		(layer "B.Cu")
		(net "FM_CPU0_PKGID0")
	)
	(segment
		(start 343.915746 -273.76882)
		(end 343.901014 -273.777456)
		(width 0.0889)
		(layer "B.Cu")
		(net "FM_CPU0_PKGID0")
	)
	(segment
		(start 295.434258 -273.36877)
		(end 294.197278 -273.36877)
		(width 0.12954)
		(layer "B.Cu")
		(net "FM_CPU0_PKGID0")
	)
	(segment
		(start 301.916338 -274.93849)
		(end 300.250098 -273.27225)
		(width 0.12954)
		(layer "B.Cu")
		(net "FM_CPU0_PKGID0")
	)
	(segment
		(start 201.07783 -152.65527)
		(end 201.07783 -150.859998)
		(width 0.12954)
		(layer "B.Cu")
		(net "FM_CPU0_PKGID0")
	)
	(segment
		(start 355.852476 -269.126208)
		(end 355.852476 -269.246858)
		(width 0.0889)
		(layer "B.Cu")
		(net "FM_CPU0_PKGID0")
	)
	(segment
		(start 346.735146 -273.76882)
		(end 346.720414 -273.777456)
		(width 0.0889)
		(layer "B.Cu")
		(net "FM_CPU0_PKGID0")
	)
	(segment
		(start 334.315816 -273.827748)
		(end 334.123792 -273.827748)
		(width 0.0889)
		(layer "B.Cu")
		(net "FM_CPU0_PKGID0")
	)
	(segment
		(start 294.197278 -273.36877)
		(end 294.105838 -273.27733)
		(width 0.12954)
		(layer "B.Cu")
		(net "FM_CPU0_PKGID0")
	)
	(segment
		(start 326.079104 -274.329144)
		(end 325.238618 -275.16963)
		(width 0.12954)
		(layer "B.Cu")
		(net "FM_CPU0_PKGID0")
	)
	(segment
		(start 356.063042 -267.755878)
		(end 355.539294 -268.279626)
		(width 0.0889)
		(layer "B.Cu")
		(net "FM_CPU0_PKGID0")
	)
	(segment
		(start 286.851344 -257.940302)
		(end 284.726634 -255.815592)
		(width 0.12954)
		(layer "B.Cu")
		(net "FM_CPU0_PKGID0")
	)
	(segment
		(start 354.71735 -271.330674)
		(end 354.70846 -271.335754)
		(width 0.0889)
		(layer "B.Cu")
		(net "FM_CPU0_PKGID0")
	)
	(segment
		(start 354.426266 -271.809718)
		(end 354.426266 -271.825212)
		(width 0.0889)
		(layer "B.Cu")
		(net "FM_CPU0_PKGID0")
	)
	(segment
		(start 347.674946 -273.76882)
		(end 347.660214 -273.777456)
		(width 0.0889)
		(layer "B.Cu")
		(net "FM_CPU0_PKGID0")
	)
	(segment
		(start 332.249526 -273.827748)
		(end 331.74813 -274.329144)
		(width 0.12954)
		(layer "B.Cu")
		(net "FM_CPU0_PKGID0")
	)
	(segment
		(start 304.042318 -276.12213)
		(end 302.858678 -274.93849)
		(width 0.12954)
		(layer "B.Cu")
		(net "FM_CPU0_PKGID0")
	)
	(segment
		(start 321.408298 -275.16963)
		(end 316.666118 -275.16963)
		(width 0.12954)
		(layer "B.Cu")
		(net "FM_CPU0_PKGID0")
	)
	(segment
		(start 315.866018 -275.96973)
		(end 311.194958 -275.96973)
		(width 0.12954)
		(layer "B.Cu")
		(net "FM_CPU0_PKGID0")
	)
	(segment
		(start 298.097956 -273.83105)
		(end 295.896538 -273.83105)
		(width 0.12954)
		(layer "B.Cu")
		(net "FM_CPU0_PKGID0")
	)
	(segment
		(start 289.06597 -271.712436)
		(end 288.111438 -270.757904)
		(width 0.12954)
		(layer "B.Cu")
		(net "FM_CPU0_PKGID0")
	)
	(segment
		(start 348.610428 -273.77136)
		(end 348.600014 -273.777456)
		(width 0.0889)
		(layer "B.Cu")
		(net "FM_CPU0_PKGID0")
	)
	(segment
		(start 355.366066 -270.175482)
		(end 355.366066 -270.19758)
		(width 0.0889)
		(layer "B.Cu")
		(net "FM_CPU0_PKGID0")
	)
	(segment
		(start 341.096346 -273.76882)
		(end 341.081614 -273.777456)
		(width 0.0889)
		(layer "B.Cu")
		(net "FM_CPU0_PKGID0")
	)
	(segment
		(start 353.394264 -272.96364)
		(end 353.379532 -272.955004)
		(width 0.0889)
		(layer "B.Cu")
		(net "FM_CPU0_PKGID0")
	)
	(segment
		(start 355.178614 -270.521938)
		(end 355.172518 -270.525494)
		(width 0.0889)
		(layer "B.Cu")
		(net "FM_CPU0_PKGID0")
	)
	(segment
		(start 306.920138 -276.12213)
		(end 304.042318 -276.12213)
		(width 0.12954)
		(layer "B.Cu")
		(net "FM_CPU0_PKGID0")
	)
	(segment
		(start 342.031828 -273.77136)
		(end 342.021414 -273.777456)
		(width 0.0889)
		(layer "B.Cu")
		(net "FM_CPU0_PKGID0")
	)
	(segment
		(start 345.795346 -273.76882)
		(end 345.780614 -273.777456)
		(width 0.0889)
		(layer "B.Cu")
		(net "FM_CPU0_PKGID0")
	)
	(segment
		(start 294.105838 -273.27733)
		(end 292.134036 -273.27733)
		(width 0.12954)
		(layer "B.Cu")
		(net "FM_CPU0_PKGID0")
	)
	(segment
		(start 355.539294 -268.279626)
		(end 355.539294 -268.813026)
		(width 0.0889)
		(layer "B.Cu")
		(net "FM_CPU0_PKGID0")
	)
	(segment
		(start 353.77755 -272.95856)
		(end 353.76866 -272.96364)
		(width 0.0889)
		(layer "B.Cu")
		(net "FM_CPU0_PKGID0")
	)
	(segment
		(start 331.74813 -274.329144)
		(end 326.079104 -274.329144)
		(width 0.12954)
		(layer "B.Cu")
		(net "FM_CPU0_PKGID0")
	)
	(segment
		(start 273.511518 -191.84747)
		(end 239.305846 -157.641798)
		(width 0.12954)
		(layer "B.Cu")
		(net "FM_CPU0_PKGID0")
	)
	(segment
		(start 352.454464 -272.96364)
		(end 352.439732 -272.955004)
		(width 0.0889)
		(layer "B.Cu")
		(net "FM_CPU0_PKGID0")
	)
	(segment
		(start 354.247704 -272.14449)
		(end 354.238814 -272.14957)
		(width 0.0889)
		(layer "B.Cu")
		(net "FM_CPU0_PKGID0")
	)
	(segment
		(start 289.435794 -271.712436)
		(end 289.06597 -271.712436)
		(width 0.12954)
		(layer "B.Cu")
		(net "FM_CPU0_PKGID0")
	)
	(segment
		(start 278.136858 -254.442468)
		(end 278.136858 -201.070972)
		(width 0.12954)
		(layer "B.Cu")
		(net "FM_CPU0_PKGID0")
	)
	(segment
		(start 279.509982 -255.815592)
		(end 278.136858 -254.442468)
		(width 0.12954)
		(layer "B.Cu")
		(net "FM_CPU0_PKGID0")
	)
	(segment
		(start 311.029858 -275.80463)
		(end 307.237638 -275.80463)
		(width 0.12954)
		(layer "B.Cu")
		(net "FM_CPU0_PKGID0")
	)
	(segment
		(start 311.194958 -275.96973)
		(end 311.029858 -275.80463)
		(width 0.12954)
		(layer "B.Cu")
		(net "FM_CPU0_PKGID0")
	)
	(segment
		(start 201.07783 -150.859998)
		(end 201.09688 -150.840948)
		(width 0.12954)
		(layer "B.Cu")
		(net "FM_CPU0_PKGID0")
	)
	(segment
		(start 344.855546 -273.76882)
		(end 344.840814 -273.777456)
		(width 0.0889)
		(layer "B.Cu")
		(net "FM_CPU0_PKGID0")
	)
	(segment
		(start 286.986218 -266.02055)
		(end 286.851344 -265.885676)
		(width 0.12954)
		(layer "B.Cu")
		(net "FM_CPU0_PKGID0")
	)
	(segment
		(start 289.762438 -272.37055)
		(end 289.762438 -272.03908)
		(width 0.12954)
		(layer "B.Cu")
		(net "FM_CPU0_PKGID0")
	)
	(segment
		(start 340.156546 -273.76882)
		(end 340.141814 -273.777456)
		(width 0.0889)
		(layer "B.Cu")
		(net "FM_CPU0_PKGID0")
	)
	(segment
		(start 288.111438 -270.757904)
		(end 288.111438 -266.45743)
		(width 0.12954)
		(layer "B.Cu")
		(net "FM_CPU0_PKGID0")
	)
	(segment
		(start 355.65715 -269.702788)
		(end 355.64826 -269.707868)
		(width 0.0889)
		(layer "B.Cu")
		(net "FM_CPU0_PKGID0")
	)
	(segment
		(start 300.250098 -273.27225)
		(end 299.701458 -273.27225)
		(width 0.12954)
		(layer "B.Cu")
		(net "FM_CPU0_PKGID0")
	)
	(segment
		(start 342.971374 -273.77136)
		(end 342.96096 -273.777456)
		(width 0.0889)
		(layer "B.Cu")
		(net "FM_CPU0_PKGID0")
	)
	(segment
		(start 307.237638 -275.80463)
		(end 306.920138 -276.12213)
		(width 0.12954)
		(layer "B.Cu")
		(net "FM_CPU0_PKGID0")
	)
	(segment
		(start 239.305846 -157.641798)
		(end 206.064358 -157.641798)
		(width 0.12954)
		(layer "B.Cu")
		(net "FM_CPU0_PKGID0")
	)
	(segment
		(start 349.549974 -273.77136)
		(end 349.53956 -273.777456)
		(width 0.0889)
		(layer "B.Cu")
		(net "FM_CPU0_PKGID0")
	)
	(segment
		(start 289.762438 -272.03908)
		(end 289.435794 -271.712436)
		(width 0.12954)
		(layer "B.Cu")
		(net "FM_CPU0_PKGID0")
	)
	(segment
		(start 353.956112 -272.625058)
		(end 353.956112 -272.639282)
		(width 0.0889)
		(layer "B.Cu")
		(net "FM_CPU0_PKGID0")
	)
	(segment
		(start 287.674558 -266.02055)
		(end 286.986218 -266.02055)
		(width 0.12954)
		(layer "B.Cu")
		(net "FM_CPU0_PKGID0")
	)
	(segment
		(start 273.511518 -196.445632)
		(end 273.511518 -191.84747)
		(width 0.12954)
		(layer "B.Cu")
		(net "FM_CPU0_PKGID0")
	)
	(segment
		(start 286.851344 -265.885676)
		(end 286.851344 -257.940302)
		(width 0.12954)
		(layer "B.Cu")
		(net "FM_CPU0_PKGID0")
	)
	(segment
		(start 298.511976 -273.41703)
		(end 298.097956 -273.83105)
		(width 0.12954)
		(layer "B.Cu")
		(net "FM_CPU0_PKGID0")
	)
	(segment
		(start 325.238618 -275.16963)
		(end 321.408298 -275.16963)
		(width 0.12954)
		(layer "B.Cu")
		(net "FM_CPU0_PKGID0")
	)
	(segment
		(start 295.896538 -273.83105)
		(end 295.434258 -273.36877)
		(width 0.12954)
		(layer "B.Cu")
		(net "FM_CPU0_PKGID0")
	)
	(segment
		(start 206.064358 -157.641798)
		(end 201.07783 -152.65527)
		(width 0.12954)
		(layer "B.Cu")
		(net "FM_CPU0_PKGID0")
	)
	(segment
		(start 292.134036 -273.27733)
		(end 291.872416 -273.53895)
		(width 0.12954)
		(layer "B.Cu")
		(net "FM_CPU0_PKGID0")
	)
	(segment
		(start 355.539294 -268.813026)
		(end 355.852476 -269.126208)
		(width 0.0889)
		(layer "B.Cu")
		(net "FM_CPU0_PKGID0")
	)
	(segment
		(start 356.400862 -267.755878)
		(end 356.063042 -267.755878)
		(width 0.0889)
		(layer "B.Cu")
		(net "FM_CPU0_PKGID0")
	)
	(segment
		(start 299.556678 -273.41703)
		(end 298.511976 -273.41703)
		(width 0.12954)
		(layer "B.Cu")
		(net "FM_CPU0_PKGID0")
	)
	(segment
		(start 288.111438 -266.45743)
		(end 287.674558 -266.02055)
		(width 0.12954)
		(layer "B.Cu")
		(net "FM_CPU0_PKGID0")
	)
	(segment
		(start 291.872416 -273.53895)
		(end 290.930838 -273.53895)
		(width 0.12954)
		(layer "B.Cu")
		(net "FM_CPU0_PKGID0")
	)
	(segment
		(start 302.858678 -274.93849)
		(end 301.916338 -274.93849)
		(width 0.12954)
		(layer "B.Cu")
		(net "FM_CPU0_PKGID0")
	)
	(segment
		(start 299.701458 -273.27225)
		(end 299.556678 -273.41703)
		(width 0.12954)
		(layer "B.Cu")
		(net "FM_CPU0_PKGID0")
	)
	(segment
		(start 316.666118 -275.16963)
		(end 315.866018 -275.96973)
		(width 0.12954)
		(layer "B.Cu")
		(net "FM_CPU0_PKGID0")
	)
	(segment
		(start 334.123792 -273.827748)
		(end 332.249526 -273.827748)
		(width 0.12954)
		(layer "B.Cu")
		(net "FM_CPU0_PKGID0")
	)
	(segment
		(start 284.726634 -255.815592)
		(end 279.509982 -255.815592)
		(width 0.12954)
		(layer "B.Cu")
		(net "FM_CPU0_PKGID0")
	)
	(segment
		(start 290.930838 -273.53895)
		(end 289.762438 -272.37055)
		(width 0.12954)
		(layer "B.Cu")
		(net "FM_CPU0_PKGID0")
	)
	(arc
		(start 354.895912 -271.011396)
		(mid 354.848233 -271.194296)
		(end 354.71735 -271.330674)
		(width 0.0889)
		(layer "B.Cu")
		(net "FM_CPU0_PKGID0")
	)
	(arc
		(start 345.406218 -273.777456)
		(mid 345.132019 -273.701621)
		(end 344.855546 -273.76882)
		(width 0.0889)
		(layer "B.Cu")
		(net "FM_CPU0_PKGID0")
	)
	(arc
		(start 351.88906 -272.96364)
		(mid 351.701862 -273.013783)
		(end 351.514664 -272.96364)
		(width 0.0889)
		(layer "B.Cu")
		(net "FM_CPU0_PKGID0")
	)
	(arc
		(start 350.666812 -273.461734)
		(mid 350.614542 -273.644099)
		(end 350.479614 -273.777456)
		(width 0.0889)
		(layer "B.Cu")
		(net "FM_CPU0_PKGID0")
	)
	(arc
		(start 339.202014 -273.777456)
		(mid 339.014816 -273.827599)
		(end 338.827618 -273.777456)
		(width 0.0889)
		(layer "B.Cu")
		(net "FM_CPU0_PKGID0")
	)
	(arc
		(start 342.96096 -273.777456)
		(mid 342.773762 -273.827599)
		(end 342.586564 -273.777456)
		(width 0.0889)
		(layer "B.Cu")
		(net "FM_CPU0_PKGID0")
	)
	(arc
		(start 341.081614 -273.777456)
		(mid 340.894416 -273.827599)
		(end 340.707218 -273.777456)
		(width 0.0889)
		(layer "B.Cu")
		(net "FM_CPU0_PKGID0")
	)
	(arc
		(start 350.94926 -272.96364)
		(mid 350.744925 -273.166245)
		(end 350.666812 -273.443192)
		(width 0.0889)
		(layer "B.Cu")
		(net "FM_CPU0_PKGID0")
	)
	(arc
		(start 352.439732 -272.955004)
		(mid 352.163257 -272.887684)
		(end 351.88906 -272.96364)
		(width 0.0889)
		(layer "B.Cu")
		(net "FM_CPU0_PKGID0")
	)
	(arc
		(start 336.947764 -273.777456)
		(mid 336.665062 -273.70168)
		(end 336.38236 -273.777456)
		(width 0.0889)
		(layer "B.Cu")
		(net "FM_CPU0_PKGID0")
	)
	(arc
		(start 340.141814 -273.777456)
		(mid 339.954616 -273.827599)
		(end 339.767418 -273.777456)
		(width 0.0889)
		(layer "B.Cu")
		(net "FM_CPU0_PKGID0")
	)
	(arc
		(start 344.466418 -273.777456)
		(mid 344.192219 -273.701621)
		(end 343.915746 -273.76882)
		(width 0.0889)
		(layer "B.Cu")
		(net "FM_CPU0_PKGID0")
	)
	(arc
		(start 354.238814 -272.14957)
		(mid 354.035333 -272.350374)
		(end 353.956112 -272.625058)
		(width 0.0889)
		(layer "B.Cu")
		(net "FM_CPU0_PKGID0")
	)
	(arc
		(start 335.44256 -273.777456)
		(mid 335.255362 -273.827599)
		(end 335.068164 -273.777456)
		(width 0.0889)
		(layer "B.Cu")
		(net "FM_CPU0_PKGID0")
	)
	(arc
		(start 336.007964 -273.777456)
		(mid 335.725262 -273.70168)
		(end 335.44256 -273.777456)
		(width 0.0889)
		(layer "B.Cu")
		(net "FM_CPU0_PKGID0")
	)
	(arc
		(start 346.720414 -273.777456)
		(mid 346.533216 -273.827599)
		(end 346.346018 -273.777456)
		(width 0.0889)
		(layer "B.Cu")
		(net "FM_CPU0_PKGID0")
	)
	(arc
		(start 355.852476 -269.246858)
		(mid 355.83992 -269.314672)
		(end 355.835712 -269.38351)
		(width 0.0889)
		(layer "B.Cu")
		(net "FM_CPU0_PKGID0")
	)
	(arc
		(start 351.514664 -272.96364)
		(mid 351.231962 -272.887864)
		(end 350.94926 -272.96364)
		(width 0.0889)
		(layer "B.Cu")
		(net "FM_CPU0_PKGID0")
	)
	(arc
		(start 353.956112 -272.639282)
		(mid 353.908433 -272.822182)
		(end 353.77755 -272.95856)
		(width 0.0889)
		(layer "B.Cu")
		(net "FM_CPU0_PKGID0")
	)
	(arc
		(start 355.366066 -270.19758)
		(mid 355.318387 -270.38048)
		(end 355.187504 -270.516858)
		(width 0.0889)
		(layer "B.Cu")
		(net "FM_CPU0_PKGID0")
	)
	(arc
		(start 345.780614 -273.777456)
		(mid 345.593416 -273.827599)
		(end 345.406218 -273.777456)
		(width 0.0889)
		(layer "B.Cu")
		(net "FM_CPU0_PKGID0")
	)
	(arc
		(start 355.64826 -269.707868)
		(mid 355.446978 -269.905355)
		(end 355.366066 -270.175482)
		(width 0.0889)
		(layer "B.Cu")
		(net "FM_CPU0_PKGID0")
	)
	(arc
		(start 337.32216 -273.777456)
		(mid 337.134962 -273.827599)
		(end 336.947764 -273.777456)
		(width 0.0889)
		(layer "B.Cu")
		(net "FM_CPU0_PKGID0")
	)
	(arc
		(start 349.165164 -273.777456)
		(mid 348.888605 -273.701713)
		(end 348.610428 -273.77136)
		(width 0.0889)
		(layer "B.Cu")
		(net "FM_CPU0_PKGID0")
	)
	(arc
		(start 347.660214 -273.777456)
		(mid 347.473016 -273.827599)
		(end 347.285818 -273.777456)
		(width 0.0889)
		(layer "B.Cu")
		(net "FM_CPU0_PKGID0")
	)
	(arc
		(start 343.901014 -273.777456)
		(mid 343.713816 -273.827599)
		(end 343.526618 -273.777456)
		(width 0.0889)
		(layer "B.Cu")
		(net "FM_CPU0_PKGID0")
	)
	(arc
		(start 338.26196 -273.777456)
		(mid 338.074762 -273.827599)
		(end 337.887564 -273.777456)
		(width 0.0889)
		(layer "B.Cu")
		(net "FM_CPU0_PKGID0")
	)
	(arc
		(start 354.70846 -271.335754)
		(mid 354.505637 -271.535985)
		(end 354.426266 -271.809718)
		(width 0.0889)
		(layer "B.Cu")
		(net "FM_CPU0_PKGID0")
	)
	(arc
		(start 334.513428 -273.77136)
		(mid 334.418567 -273.813382)
		(end 334.315816 -273.827748)
		(width 0.0889)
		(layer "B.Cu")
		(net "FM_CPU0_PKGID0")
	)
	(arc
		(start 352.82886 -272.96364)
		(mid 352.641662 -273.013783)
		(end 352.454464 -272.96364)
		(width 0.0889)
		(layer "B.Cu")
		(net "FM_CPU0_PKGID0")
	)
	(arc
		(start 355.172518 -270.525494)
		(mid 354.969931 -270.731845)
		(end 354.895912 -271.011396)
		(width 0.0889)
		(layer "B.Cu")
		(net "FM_CPU0_PKGID0")
	)
	(arc
		(start 336.38236 -273.777456)
		(mid 336.195162 -273.827599)
		(end 336.007964 -273.777456)
		(width 0.0889)
		(layer "B.Cu")
		(net "FM_CPU0_PKGID0")
	)
	(arc
		(start 353.76866 -272.96364)
		(mid 353.581462 -273.013783)
		(end 353.394264 -272.96364)
		(width 0.0889)
		(layer "B.Cu")
		(net "FM_CPU0_PKGID0")
	)
	(arc
		(start 337.887564 -273.777456)
		(mid 337.604862 -273.70168)
		(end 337.32216 -273.777456)
		(width 0.0889)
		(layer "B.Cu")
		(net "FM_CPU0_PKGID0")
	)
	(arc
		(start 346.346018 -273.777456)
		(mid 346.071819 -273.701621)
		(end 345.795346 -273.76882)
		(width 0.0889)
		(layer "B.Cu")
		(net "FM_CPU0_PKGID0")
	)
	(arc
		(start 343.526618 -273.777456)
		(mid 343.249805 -273.701586)
		(end 342.971374 -273.77136)
		(width 0.0889)
		(layer "B.Cu")
		(net "FM_CPU0_PKGID0")
	)
	(arc
		(start 341.647018 -273.777456)
		(mid 341.372819 -273.701621)
		(end 341.096346 -273.76882)
		(width 0.0889)
		(layer "B.Cu")
		(net "FM_CPU0_PKGID0")
	)
	(arc
		(start 349.53956 -273.777456)
		(mid 349.352362 -273.827599)
		(end 349.165164 -273.777456)
		(width 0.0889)
		(layer "B.Cu")
		(net "FM_CPU0_PKGID0")
	)
	(arc
		(start 335.068164 -273.777456)
		(mid 334.791605 -273.701713)
		(end 334.513428 -273.77136)
		(width 0.0889)
		(layer "B.Cu")
		(net "FM_CPU0_PKGID0")
	)
	(arc
		(start 353.379532 -272.955004)
		(mid 353.103057 -272.887684)
		(end 352.82886 -272.96364)
		(width 0.0889)
		(layer "B.Cu")
		(net "FM_CPU0_PKGID0")
	)
	(arc
		(start 348.225618 -273.777456)
		(mid 347.951419 -273.701621)
		(end 347.674946 -273.76882)
		(width 0.0889)
		(layer "B.Cu")
		(net "FM_CPU0_PKGID0")
	)
	(arc
		(start 350.479614 -273.777456)
		(mid 350.292416 -273.827599)
		(end 350.105218 -273.777456)
		(width 0.0889)
		(layer "B.Cu")
		(net "FM_CPU0_PKGID0")
	)
	(arc
		(start 348.600014 -273.777456)
		(mid 348.412816 -273.827599)
		(end 348.225618 -273.777456)
		(width 0.0889)
		(layer "B.Cu")
		(net "FM_CPU0_PKGID0")
	)
	(arc
		(start 338.827618 -273.777456)
		(mid 338.550805 -273.701586)
		(end 338.272374 -273.77136)
		(width 0.0889)
		(layer "B.Cu")
		(net "FM_CPU0_PKGID0")
	)
	(arc
		(start 344.840814 -273.777456)
		(mid 344.653616 -273.827599)
		(end 344.466418 -273.777456)
		(width 0.0889)
		(layer "B.Cu")
		(net "FM_CPU0_PKGID0")
	)
	(arc
		(start 339.767418 -273.777456)
		(mid 339.484716 -273.70168)
		(end 339.202014 -273.777456)
		(width 0.0889)
		(layer "B.Cu")
		(net "FM_CPU0_PKGID0")
	)
	(arc
		(start 350.105218 -273.777456)
		(mid 349.828405 -273.701586)
		(end 349.549974 -273.77136)
		(width 0.0889)
		(layer "B.Cu")
		(net "FM_CPU0_PKGID0")
	)
	(arc
		(start 342.586564 -273.777456)
		(mid 342.310005 -273.701713)
		(end 342.031828 -273.77136)
		(width 0.0889)
		(layer "B.Cu")
		(net "FM_CPU0_PKGID0")
	)
	(arc
		(start 340.707218 -273.777456)
		(mid 340.433019 -273.701621)
		(end 340.156546 -273.76882)
		(width 0.0889)
		(layer "B.Cu")
		(net "FM_CPU0_PKGID0")
	)
	(arc
		(start 354.426266 -271.825212)
		(mid 354.378587 -272.008112)
		(end 354.247704 -272.14449)
		(width 0.0889)
		(layer "B.Cu")
		(net "FM_CPU0_PKGID0")
	)
	(arc
		(start 347.285818 -273.777456)
		(mid 347.011619 -273.701621)
		(end 346.735146 -273.76882)
		(width 0.0889)
		(layer "B.Cu")
		(net "FM_CPU0_PKGID0")
	)
	(arc
		(start 342.021414 -273.777456)
		(mid 341.834216 -273.827599)
		(end 341.647018 -273.777456)
		(width 0.0889)
		(layer "B.Cu")
		(net "FM_CPU0_PKGID0")
	)
	(arc
		(start 355.835712 -269.38351)
		(mid 355.788033 -269.56641)
		(end 355.65715 -269.702788)
		(width 0.0889)
		(layer "B.Cu")
		(net "FM_CPU0_PKGID0")
	)
	(segment
		(start 182.89524 -126.538228)
		(end 180.56606 -124.209048)
		(width 0.127)
		(layer "In2.Cu")
		(net "FM_CPU0_PKGID0")
	)
	(segment
		(start 199.55891 -150.063454)
		(end 198.428864 -149.595332)
		(width 0.127)
		(layer "In2.Cu")
		(net "FM_CPU0_PKGID0")
	)
	(segment
		(start 182.90794 -141.017244)
		(end 182.90794 -130.045968)
		(width 0.127)
		(layer "In2.Cu")
		(net "FM_CPU0_PKGID0")
	)
	(segment
		(start 196.34708 -147.513548)
		(end 189.404244 -147.513548)
		(width 0.127)
		(layer "In2.Cu")
		(net "FM_CPU0_PKGID0")
	)
	(segment
		(start 182.90794 -130.045968)
		(end 183.69788 -129.256028)
		(width 0.127)
		(layer "In2.Cu")
		(net "FM_CPU0_PKGID0")
	)
	(segment
		(start 189.404244 -147.513548)
		(end 182.90794 -141.017244)
		(width 0.127)
		(layer "In2.Cu")
		(net "FM_CPU0_PKGID0")
	)
	(segment
		(start 200.336404 -150.840948)
		(end 199.55891 -150.063454)
		(width 0.127)
		(layer "In2.Cu")
		(net "FM_CPU0_PKGID0")
	)
	(segment
		(start 198.428864 -149.595332)
		(end 196.34708 -147.513548)
		(width 0.127)
		(layer "In2.Cu")
		(net "FM_CPU0_PKGID0")
	)
	(segment
		(start 180.56606 -124.209048)
		(end 180.56606 -120.986042)
		(width 0.127)
		(layer "In2.Cu")
		(net "FM_CPU0_PKGID0")
	)
	(segment
		(start 201.09688 -150.840948)
		(end 200.336404 -150.840948)
		(width 0.127)
		(layer "In2.Cu")
		(net "FM_CPU0_PKGID0")
	)
	(segment
		(start 183.69788 -129.256028)
		(end 182.89524 -128.453388)
		(width 0.127)
		(layer "In2.Cu")
		(net "FM_CPU0_PKGID0")
	)
	(segment
		(start 182.89524 -128.453388)
		(end 182.89524 -126.538228)
		(width 0.127)
		(layer "In2.Cu")
		(net "FM_CPU0_PKGID0")
	)
	(segment
		(start 180.56606 -120.986042)
		(end 180.155596 -120.575578)
		(width 0.127)
		(layer "In2.Cu")
		(net "FM_CPU0_PKGID0")
	)
	(segment
		(start 216.67978 -130.923538)
		(end 217.69324 -130.923538)
		(width 0.12954)
		(layer "F.Cu")
		(net "FM_COMP_P3V3_STBY_CEXT")
	)
	(segment
		(start 212.82025 -134.065518)
		(end 214.194898 -134.065518)
		(width 0.12954)
		(layer "F.Cu")
		(net "FM_COMP_P3V3_STBY_CEXT")
	)
	(segment
		(start 217.69324 -130.923538)
		(end 217.72753 -130.957828)
		(width 0.12954)
		(layer "F.Cu")
		(net "FM_COMP_P3V3_STBY_CEXT")
	)
	(segment
		(start 214.752682 -130.923538)
		(end 216.67978 -130.923538)
		(width 0.12954)
		(layer "F.Cu")
		(net "FM_COMP_P3V3_STBY_CEXT")
	)
	(via
		(at 214.194898 -134.065518)
		(size 0.508)
		(drill 0.254)
		(layers "F.Cu" "B.Cu")
		(net "FM_COMP_P3V3_STBY_CEXT")
	)
	(via
		(at 216.67978 -130.923538)
		(size 0.508)
		(drill 0.254)
		(layers "F.Cu" "B.Cu")
		(net "FM_COMP_P3V3_STBY_CEXT")
	)
	(segment
		(start 216.67978 -130.923538)
		(end 216.67978 -131.580636)
		(width 0.127)
		(layer "In13.Cu")
		(net "FM_COMP_P3V3_STBY_CEXT")
	)
	(segment
		(start 216.67978 -131.580636)
		(end 214.194898 -134.065518)
		(width 0.127)
		(layer "In13.Cu")
		(net "FM_COMP_P3V3_STBY_CEXT")
	)
	(segment
		(start 159.97428 -131.255008)
		(end 159.23514 -131.255008)
		(width 0.12954)
		(layer "F.Cu")
		(net "FM_COMP_P3V3_AUX_VIN_R")
	)
	(segment
		(start 158.136082 -130.15595)
		(end 157.28188 -130.15595)
		(width 0.12954)
		(layer "F.Cu")
		(net "FM_COMP_P3V3_AUX_VIN_R")
	)
	(segment
		(start 159.23514 -131.255008)
		(end 158.136082 -130.15595)
		(width 0.12954)
		(layer "F.Cu")
		(net "FM_COMP_P3V3_AUX_VIN_R")
	)
	(segment
		(start 159.99968 -131.229608)
		(end 159.97428 -131.255008)
		(width 0.12954)
		(layer "F.Cu")
		(net "FM_COMP_P3V3_AUX_VIN_R")
	)
	(segment
		(start 209.34553 -129.814828)
		(end 208.71688 -129.814828)
		(width 0.12954)
		(layer "F.Cu")
		(net "FM_COMP_P3V3_AUX_VIN_R")
	)
	(via
		(at 159.99968 -131.229608)
		(size 0.508)
		(drill 0.254)
		(layers "F.Cu" "B.Cu")
		(net "FM_COMP_P3V3_AUX_VIN_R")
	)
	(via
		(at 208.71688 -129.814828)
		(size 0.508)
		(drill 0.254)
		(layers "F.Cu" "B.Cu")
		(net "FM_COMP_P3V3_AUX_VIN_R")
	)
	(segment
		(start 196.0499 -133.607048)
		(end 202.81392 -133.607048)
		(width 0.127)
		(layer "In15.Cu")
		(net "FM_COMP_P3V3_AUX_VIN_R")
	)
	(segment
		(start 186.4741 -128.742948)
		(end 187.1726 -128.742948)
		(width 0.127)
		(layer "In15.Cu")
		(net "FM_COMP_P3V3_AUX_VIN_R")
	)
	(segment
		(start 206.06004 -130.360928)
		(end 208.31302 -130.360928)
		(width 0.127)
		(layer "In15.Cu")
		(net "FM_COMP_P3V3_AUX_VIN_R")
	)
	(segment
		(start 174.423324 -132.228336)
		(end 174.838868 -131.812792)
		(width 0.127)
		(layer "In15.Cu")
		(net "FM_COMP_P3V3_AUX_VIN_R")
	)
	(segment
		(start 162.3695 -130.518408)
		(end 162.61334 -130.762248)
		(width 0.127)
		(layer "In15.Cu")
		(net "FM_COMP_P3V3_AUX_VIN_R")
	)
	(segment
		(start 175.239426 -130.503168)
		(end 177.416206 -130.503168)
		(width 0.127)
		(layer "In15.Cu")
		(net "FM_COMP_P3V3_AUX_VIN_R")
	)
	(segment
		(start 191.687704 -132.464556)
		(end 194.907408 -132.464556)
		(width 0.127)
		(layer "In15.Cu")
		(net "FM_COMP_P3V3_AUX_VIN_R")
	)
	(segment
		(start 165.14318 -131.463288)
		(end 167.39616 -131.463288)
		(width 0.127)
		(layer "In15.Cu")
		(net "FM_COMP_P3V3_AUX_VIN_R")
	)
	(segment
		(start 174.838868 -130.903726)
		(end 175.239426 -130.503168)
		(width 0.127)
		(layer "In15.Cu")
		(net "FM_COMP_P3V3_AUX_VIN_R")
	)
	(segment
		(start 194.907408 -132.464556)
		(end 196.0499 -133.607048)
		(width 0.127)
		(layer "In15.Cu")
		(net "FM_COMP_P3V3_AUX_VIN_R")
	)
	(segment
		(start 172.128942 -130.9116)
		(end 172.128942 -131.665726)
		(width 0.127)
		(layer "In15.Cu")
		(net "FM_COMP_P3V3_AUX_VIN_R")
	)
	(segment
		(start 162.61334 -130.762248)
		(end 164.44214 -130.762248)
		(width 0.127)
		(layer "In15.Cu")
		(net "FM_COMP_P3V3_AUX_VIN_R")
	)
	(segment
		(start 184.552336 -130.664712)
		(end 186.4741 -128.742948)
		(width 0.127)
		(layer "In15.Cu")
		(net "FM_COMP_P3V3_AUX_VIN_R")
	)
	(segment
		(start 187.1726 -128.742948)
		(end 189.11824 -130.688588)
		(width 0.127)
		(layer "In15.Cu")
		(net "FM_COMP_P3V3_AUX_VIN_R")
	)
	(segment
		(start 208.31302 -130.360928)
		(end 208.71688 -129.957068)
		(width 0.127)
		(layer "In15.Cu")
		(net "FM_COMP_P3V3_AUX_VIN_R")
	)
	(segment
		(start 174.838868 -131.812792)
		(end 174.838868 -130.903726)
		(width 0.127)
		(layer "In15.Cu")
		(net "FM_COMP_P3V3_AUX_VIN_R")
	)
	(segment
		(start 167.39616 -131.463288)
		(end 168.074848 -130.7846)
		(width 0.127)
		(layer "In15.Cu")
		(net "FM_COMP_P3V3_AUX_VIN_R")
	)
	(segment
		(start 189.11824 -130.688588)
		(end 189.40272 -130.688588)
		(width 0.127)
		(layer "In15.Cu")
		(net "FM_COMP_P3V3_AUX_VIN_R")
	)
	(segment
		(start 172.128942 -131.665726)
		(end 172.691552 -132.228336)
		(width 0.127)
		(layer "In15.Cu")
		(net "FM_COMP_P3V3_AUX_VIN_R")
	)
	(segment
		(start 172.691552 -132.228336)
		(end 174.423324 -132.228336)
		(width 0.127)
		(layer "In15.Cu")
		(net "FM_COMP_P3V3_AUX_VIN_R")
	)
	(segment
		(start 177.416206 -130.503168)
		(end 178.7779 -131.864862)
		(width 0.127)
		(layer "In15.Cu")
		(net "FM_COMP_P3V3_AUX_VIN_R")
	)
	(segment
		(start 178.7779 -131.864862)
		(end 183.851042 -131.864862)
		(width 0.127)
		(layer "In15.Cu")
		(net "FM_COMP_P3V3_AUX_VIN_R")
	)
	(segment
		(start 159.99968 -131.229608)
		(end 160.71088 -130.518408)
		(width 0.127)
		(layer "In15.Cu")
		(net "FM_COMP_P3V3_AUX_VIN_R")
	)
	(segment
		(start 189.40272 -130.688588)
		(end 190.625984 -131.911852)
		(width 0.127)
		(layer "In15.Cu")
		(net "FM_COMP_P3V3_AUX_VIN_R")
	)
	(segment
		(start 191.135 -131.911852)
		(end 191.687704 -132.464556)
		(width 0.127)
		(layer "In15.Cu")
		(net "FM_COMP_P3V3_AUX_VIN_R")
	)
	(segment
		(start 208.71688 -129.957068)
		(end 208.71688 -129.814828)
		(width 0.127)
		(layer "In15.Cu")
		(net "FM_COMP_P3V3_AUX_VIN_R")
	)
	(segment
		(start 160.71088 -130.518408)
		(end 162.3695 -130.518408)
		(width 0.127)
		(layer "In15.Cu")
		(net "FM_COMP_P3V3_AUX_VIN_R")
	)
	(segment
		(start 184.552336 -131.163568)
		(end 184.552336 -130.664712)
		(width 0.127)
		(layer "In15.Cu")
		(net "FM_COMP_P3V3_AUX_VIN_R")
	)
	(segment
		(start 172.001942 -130.7846)
		(end 172.128942 -130.9116)
		(width 0.127)
		(layer "In15.Cu")
		(net "FM_COMP_P3V3_AUX_VIN_R")
	)
	(segment
		(start 164.44214 -130.762248)
		(end 165.14318 -131.463288)
		(width 0.127)
		(layer "In15.Cu")
		(net "FM_COMP_P3V3_AUX_VIN_R")
	)
	(segment
		(start 183.851042 -131.864862)
		(end 184.552336 -131.163568)
		(width 0.127)
		(layer "In15.Cu")
		(net "FM_COMP_P3V3_AUX_VIN_R")
	)
	(segment
		(start 190.625984 -131.911852)
		(end 191.135 -131.911852)
		(width 0.127)
		(layer "In15.Cu")
		(net "FM_COMP_P3V3_AUX_VIN_R")
	)
	(segment
		(start 202.81392 -133.607048)
		(end 206.06004 -130.360928)
		(width 0.127)
		(layer "In15.Cu")
		(net "FM_COMP_P3V3_AUX_VIN_R")
	)
	(segment
		(start 168.074848 -130.7846)
		(end 172.001942 -130.7846)
		(width 0.127)
		(layer "In15.Cu")
		(net "FM_COMP_P3V3_AUX_VIN_R")
	)
	(segment
		(start 210.14563 -129.814828)
		(end 210.14563 -130.830828)
		(width 0.12954)
		(layer "F.Cu")
		(net "FM_COMP_P3V3_AUX_VIN")
	)
	(segment
		(start 210.14563 -131.846828)
		(end 210.14563 -130.830828)
		(width 0.12954)
		(layer "F.Cu")
		(net "FM_COMP_P3V3_AUX_VIN")
	)
	(segment
		(start 210.14563 -129.814828)
		(end 210.604354 -130.273552)
		(width 0.12954)
		(layer "F.Cu")
		(net "FM_COMP_P3V3_AUX_VIN")
	)
	(segment
		(start 211.47786 -130.273552)
		(end 213.11489 -130.273552)
		(width 0.12954)
		(layer "F.Cu")
		(net "FM_COMP_P3V3_AUX_VIN")
	)
	(segment
		(start 212.070188 -133.565646)
		(end 211.42198 -133.565646)
		(width 0.12954)
		(layer "F.Cu")
		(net "FM_COMP_P3V3_AUX_VIN")
	)
	(segment
		(start 210.604354 -130.273552)
		(end 211.47786 -130.273552)
		(width 0.12954)
		(layer "F.Cu")
		(net "FM_COMP_P3V3_AUX_VIN")
	)
	(via
		(at 211.47786 -130.273552)
		(size 0.508)
		(drill 0.254)
		(layers "F.Cu" "B.Cu")
		(net "FM_COMP_P3V3_AUX_VIN")
	)
	(via
		(at 211.42198 -133.565646)
		(size 0.508)
		(drill 0.254)
		(layers "F.Cu" "B.Cu")
		(net "FM_COMP_P3V3_AUX_VIN")
	)
	(segment
		(start 211.42198 -133.565646)
		(end 211.42198 -130.329432)
		(width 0.127)
		(layer "In13.Cu")
		(net "FM_COMP_P3V3_AUX_VIN")
	)
	(segment
		(start 211.42198 -130.329432)
		(end 211.47786 -130.273552)
		(width 0.127)
		(layer "In13.Cu")
		(net "FM_COMP_P3V3_AUX_VIN")
	)
	(segment
		(start 211.35975 -132.373624)
		(end 210.870546 -132.862828)
		(width 0.12954)
		(layer "F.Cu")
		(net "FM_COMP_P3V3_AUX_ENIN")
	)
	(segment
		(start 212.15985 -131.573524)
		(end 211.35975 -132.373624)
		(width 0.12954)
		(layer "F.Cu")
		(net "FM_COMP_P3V3_AUX_ENIN")
	)
	(segment
		(start 212.065362 -134.565644)
		(end 210.45043 -134.565644)
		(width 0.12954)
		(layer "F.Cu")
		(net "FM_COMP_P3V3_AUX_ENIN")
	)
	(segment
		(start 210.14563 -133.878828)
		(end 210.14563 -132.862828)
		(width 0.12954)
		(layer "F.Cu")
		(net "FM_COMP_P3V3_AUX_ENIN")
	)
	(segment
		(start 210.14563 -134.260844)
		(end 210.14563 -133.878828)
		(width 0.12954)
		(layer "F.Cu")
		(net "FM_COMP_P3V3_AUX_ENIN")
	)
	(segment
		(start 210.45043 -134.565644)
		(end 210.14563 -134.260844)
		(width 0.12954)
		(layer "F.Cu")
		(net "FM_COMP_P3V3_AUX_ENIN")
	)
	(segment
		(start 213.11489 -131.573524)
		(end 212.15985 -131.573524)
		(width 0.12954)
		(layer "F.Cu")
		(net "FM_COMP_P3V3_AUX_ENIN")
	)
	(segment
		(start 210.870546 -132.862828)
		(end 210.14563 -132.862828)
		(width 0.12954)
		(layer "F.Cu")
		(net "FM_COMP_P3V3_AUX_ENIN")
	)
	(via
		(at 211.35975 -132.373624)
		(size 0.762)
		(drill 0.381)
		(layers "F.Cu" "B.Cu")
		(net "FM_COMP_P3V3_AUX_ENIN")
	)
	(segment
		(start 261.877556 -99.063302)
		(end 261.912862 -99.098608)
		(width 0.0889)
		(layer "F.Cu")
		(net "FM_CLK_GEN1_OE0_N")
	)
	(segment
		(start 258.807712 -99.063302)
		(end 261.877556 -99.063302)
		(width 0.0889)
		(layer "F.Cu")
		(net "FM_CLK_GEN1_OE0_N")
	)
	(via
		(at 261.912862 -99.098608)
		(size 0.508)
		(drill 0.254)
		(layers "F.Cu" "B.Cu")
		(net "FM_CLK_GEN1_OE0_N")
	)
	(segment
		(start 261.912862 -99.098608)
		(end 261.961122 -99.050348)
		(width 0.12954)
		(layer "B.Cu")
		(net "FM_CLK_GEN1_OE0_N")
	)
	(segment
		(start 261.961122 -99.050348)
		(end 263.064752 -99.050348)
		(width 0.12954)
		(layer "B.Cu")
		(net "FM_CLK_GEN1_OE0_N")
	)
	(segment
		(start 251.361194 -93.8911)
		(end 251.135642 -93.8911)
		(width 0.12954)
		(layer "F.Cu")
		(net "FM_CLK_CK440_SS_EN")
	)
	(segment
		(start 252.932692 -95.68815)
		(end 252.932692 -95.462598)
		(width 0.12954)
		(layer "F.Cu")
		(net "FM_CLK_CK440_SS_EN")
	)
	(segment
		(start 252.932692 -95.462598)
		(end 251.361194 -93.8911)
		(width 0.12954)
		(layer "F.Cu")
		(net "FM_CLK_CK440_SS_EN")
	)
	(via
		(at 251.159772 -87.978488)
		(size 0.508)
		(drill 0.254)
		(layers "F.Cu" "B.Cu")
		(net "FM_CLK_CK440_SS_EN")
	)
	(via
		(at 251.135642 -93.8911)
		(size 0.508)
		(drill 0.254)
		(layers "F.Cu" "B.Cu")
		(net "FM_CLK_CK440_SS_EN")
	)
	(segment
		(start 251.552456 -86.824566)
		(end 253.868936 -86.824566)
		(width 0.12954)
		(layer "B.Cu")
		(net "FM_CLK_CK440_SS_EN")
	)
	(segment
		(start 251.159772 -87.978488)
		(end 251.544836 -87.593424)
		(width 0.12954)
		(layer "B.Cu")
		(net "FM_CLK_CK440_SS_EN")
	)
	(segment
		(start 251.544836 -87.593424)
		(end 251.544836 -86.816946)
		(width 0.12954)
		(layer "B.Cu")
		(net "FM_CLK_CK440_SS_EN")
	)
	(segment
		(start 251.544836 -86.816946)
		(end 251.552456 -86.824566)
		(width 0.12954)
		(layer "B.Cu")
		(net "FM_CLK_CK440_SS_EN")
	)
	(segment
		(start 251.135642 -93.8911)
		(end 251.135642 -88.002618)
		(width 0.127)
		(layer "In15.Cu")
		(net "FM_CLK_CK440_SS_EN")
	)
	(segment
		(start 251.135642 -88.002618)
		(end 251.159772 -87.978488)
		(width 0.127)
		(layer "In15.Cu")
		(net "FM_CLK_CK440_SS_EN")
	)
	(segment
		(start 256.64668 -105.171494)
		(end 256.64668 -105.679748)
		(width 0.0889)
		(layer "F.Cu")
		(net "FM_CK440_MXCK_25M_100M")
	)
	(segment
		(start 256.182622 -104.707436)
		(end 256.64668 -105.171494)
		(width 0.0889)
		(layer "F.Cu")
		(net "FM_CK440_MXCK_25M_100M")
	)
	(segment
		(start 256.182622 -102.688136)
		(end 256.182622 -104.707436)
		(width 0.0889)
		(layer "F.Cu")
		(net "FM_CK440_MXCK_25M_100M")
	)
	(via
		(at 256.64668 -105.679748)
		(size 0.508)
		(drill 0.254)
		(layers "F.Cu" "B.Cu")
		(net "FM_CK440_MXCK_25M_100M")
	)
	(segment
		(start 257.984752 -106.819192)
		(end 257.984752 -105.911396)
		(width 0.12954)
		(layer "B.Cu")
		(net "FM_CK440_MXCK_25M_100M")
	)
	(segment
		(start 256.64668 -105.679748)
		(end 256.878328 -105.911396)
		(width 0.12954)
		(layer "B.Cu")
		(net "FM_CK440_MXCK_25M_100M")
	)
	(segment
		(start 256.878328 -105.911396)
		(end 257.984752 -105.911396)
		(width 0.12954)
		(layer "B.Cu")
		(net "FM_CK440_MXCK_25M_100M")
	)
	(segment
		(start 251.807726 -103.696008)
		(end 251.807726 -102.813104)
		(width 0.12954)
		(layer "F.Cu")
		(net "FM_CK440Q_DEV_25M_EN")
	)
	(via
		(at 251.807726 -103.696008)
		(size 0.508)
		(drill 0.254)
		(layers "F.Cu" "B.Cu")
		(net "FM_CK440Q_DEV_25M_EN")
	)
	(segment
		(start 252.05563 -104.856534)
		(end 251.007626 -104.856534)
		(width 0.12954)
		(layer "B.Cu")
		(net "FM_CK440Q_DEV_25M_EN")
	)
	(segment
		(start 251.807726 -103.696008)
		(end 252.05563 -103.943912)
		(width 0.12954)
		(layer "B.Cu")
		(net "FM_CK440Q_DEV_25M_EN")
	)
	(segment
		(start 252.05563 -103.943912)
		(end 252.05563 -104.856534)
		(width 0.12954)
		(layer "B.Cu")
		(net "FM_CK440Q_DEV_25M_EN")
	)
	(segment
		(start 250.000516 -104.856534)
		(end 248.943368 -104.856534)
		(width 0.12954)
		(layer "B.Cu")
		(net "FM_CK440Q_DEV_25M_EN")
	)
	(segment
		(start 251.007626 -104.856534)
		(end 250.000516 -104.856534)
		(width 0.12954)
		(layer "B.Cu")
		(net "FM_CK440Q_DEV_25M_EN")
	)
	(segment
		(start 320.8401 -76.185014)
		(end 320.8401 -74.860404)
		(width 0.12954)
		(layer "F.Cu")
		(net "FM_BOARD_SKU_ID4")
	)
	(segment
		(start 319.8241 -76.185014)
		(end 320.8401 -76.185014)
		(width 0.12954)
		(layer "F.Cu")
		(net "FM_BOARD_SKU_ID4")
	)
	(segment
		(start 331.73543 -49.859946)
		(end 331.608176 -49.732692)
		(width 0.12954)
		(layer "F.Cu")
		(net "FM_BOARD_SKU_ID4")
	)
	(segment
		(start 331.608176 -49.732692)
		(end 331.608176 -49.390046)
		(width 0.12954)
		(layer "F.Cu")
		(net "FM_BOARD_SKU_ID4")
	)
	(segment
		(start 331.880718 -49.859946)
		(end 331.73543 -49.859946)
		(width 0.12954)
		(layer "F.Cu")
		(net "FM_BOARD_SKU_ID4")
	)
	(via
		(at 320.8401 -74.860404)
		(size 0.508)
		(drill 0.254)
		(layers "F.Cu" "B.Cu")
		(net "FM_BOARD_SKU_ID4")
	)
	(via
		(at 331.880718 -49.859946)
		(size 0.4572)
		(drill 0.2032)
		(layers "F.Cu" "B.Cu")
		(net "FM_BOARD_SKU_ID4")
	)
	(segment
		(start 331.457554 -51.946556)
		(end 331.47381 -51.974496)
		(width 0.127)
		(layer "In11.Cu")
		(net "FM_BOARD_SKU_ID4")
	)
	(segment
		(start 331.47508 -53.854096)
		(end 331.485494 -53.871876)
		(width 0.127)
		(layer "In11.Cu")
		(net "FM_BOARD_SKU_ID4")
	)
	(segment
		(start 331.465682 -56.655716)
		(end 331.476096 -56.673496)
		(width 0.127)
		(layer "In11.Cu")
		(net "FM_BOARD_SKU_ID4")
	)
	(segment
		(start 331.465682 -52.896516)
		(end 331.476096 -52.914296)
		(width 0.127)
		(layer "In11.Cu")
		(net "FM_BOARD_SKU_ID4")
	)
	(segment
		(start 331.47381 -51.974496)
		(end 331.493114 -52.007516)
		(width 0.127)
		(layer "In11.Cu")
		(net "FM_BOARD_SKU_ID4")
	)
	(segment
		(start 331.880718 -49.859946)
		(end 331.880718 -50.157126)
		(width 0.127)
		(layer "In11.Cu")
		(net "FM_BOARD_SKU_ID4")
	)
	(segment
		(start 331.476096 -53.384196)
		(end 331.47508 -53.854096)
		(width 0.127)
		(layer "In11.Cu")
		(net "FM_BOARD_SKU_ID4")
	)
	(segment
		(start 326.06488 -69.611748)
		(end 326.06488 -70.424548)
		(width 0.127)
		(layer "In11.Cu")
		(net "FM_BOARD_SKU_ID4")
	)
	(segment
		(start 331.14488 -59.908948)
		(end 331.14488 -64.531748)
		(width 0.127)
		(layer "In11.Cu")
		(net "FM_BOARD_SKU_ID4")
	)
	(segment
		(start 331.476096 -57.143396)
		(end 331.465682 -57.161176)
		(width 0.127)
		(layer "In11.Cu")
		(net "FM_BOARD_SKU_ID4")
	)
	(segment
		(start 326.06488 -70.424548)
		(end 321.629024 -74.860404)
		(width 0.127)
		(layer "In11.Cu")
		(net "FM_BOARD_SKU_ID4")
	)
	(segment
		(start 331.880718 -50.157126)
		(end 331.473048 -50.564796)
		(width 0.127)
		(layer "In11.Cu")
		(net "FM_BOARD_SKU_ID4")
	)
	(segment
		(start 331.465174 -55.715916)
		(end 331.475588 -55.733696)
		(width 0.127)
		(layer "In11.Cu")
		(net "FM_BOARD_SKU_ID4")
	)
	(segment
		(start 331.482954 -51.486816)
		(end 331.47254 -51.504596)
		(width 0.127)
		(layer "In11.Cu")
		(net "FM_BOARD_SKU_ID4")
	)
	(segment
		(start 331.14488 -64.531748)
		(end 326.06488 -69.611748)
		(width 0.127)
		(layer "In11.Cu")
		(net "FM_BOARD_SKU_ID4")
	)
	(segment
		(start 331.485494 -55.246016)
		(end 331.47508 -55.263796)
		(width 0.127)
		(layer "In11.Cu")
		(net "FM_BOARD_SKU_ID4")
	)
	(segment
		(start 321.629024 -74.860404)
		(end 320.8401 -74.860404)
		(width 0.127)
		(layer "In11.Cu")
		(net "FM_BOARD_SKU_ID4")
	)
	(segment
		(start 331.475588 -59.57824)
		(end 331.14488 -59.908948)
		(width 0.127)
		(layer "In11.Cu")
		(net "FM_BOARD_SKU_ID4")
	)
	(segment
		(start 331.475588 -59.492896)
		(end 331.475588 -59.57824)
		(width 0.127)
		(layer "In11.Cu")
		(net "FM_BOARD_SKU_ID4")
	)
	(arc
		(start 331.475588 -58.083196)
		(mid 331.41256 -58.318146)
		(end 331.475588 -58.553096)
		(width 0.127)
		(layer "In11.Cu")
		(net "FM_BOARD_SKU_ID4")
	)
	(arc
		(start 331.485494 -53.871876)
		(mid 331.538358 -54.09919)
		(end 331.475588 -54.323996)
		(width 0.127)
		(layer "In11.Cu")
		(net "FM_BOARD_SKU_ID4")
	)
	(arc
		(start 331.475588 -54.793896)
		(mid 331.538458 -55.0187)
		(end 331.485494 -55.246016)
		(width 0.127)
		(layer "In11.Cu")
		(net "FM_BOARD_SKU_ID4")
	)
	(arc
		(start 331.476096 -52.914296)
		(mid 331.539056 -53.149246)
		(end 331.476096 -53.384196)
		(width 0.127)
		(layer "In11.Cu")
		(net "FM_BOARD_SKU_ID4")
	)
	(arc
		(start 331.47254 -51.504596)
		(mid 331.409916 -51.723695)
		(end 331.457554 -51.946556)
		(width 0.127)
		(layer "In11.Cu")
		(net "FM_BOARD_SKU_ID4")
	)
	(arc
		(start 331.476096 -56.673496)
		(mid 331.539158 -56.908446)
		(end 331.476096 -57.143396)
		(width 0.127)
		(layer "In11.Cu")
		(net "FM_BOARD_SKU_ID4")
	)
	(arc
		(start 331.475588 -54.323996)
		(mid 331.41273 -54.558946)
		(end 331.475588 -54.793896)
		(width 0.127)
		(layer "In11.Cu")
		(net "FM_BOARD_SKU_ID4")
	)
	(arc
		(start 331.475588 -56.203596)
		(mid 331.41267 -56.428371)
		(end 331.465682 -56.655716)
		(width 0.127)
		(layer "In11.Cu")
		(net "FM_BOARD_SKU_ID4")
	)
	(arc
		(start 331.475588 -52.444396)
		(mid 331.412718 -52.6692)
		(end 331.465682 -52.896516)
		(width 0.127)
		(layer "In11.Cu")
		(net "FM_BOARD_SKU_ID4")
	)
	(arc
		(start 331.475588 -55.733696)
		(mid 331.538616 -55.968646)
		(end 331.475588 -56.203596)
		(width 0.127)
		(layer "In11.Cu")
		(net "FM_BOARD_SKU_ID4")
	)
	(arc
		(start 331.475588 -57.613296)
		(mid 331.538616 -57.848246)
		(end 331.475588 -58.083196)
		(width 0.127)
		(layer "In11.Cu")
		(net "FM_BOARD_SKU_ID4")
	)
	(arc
		(start 331.475588 -58.553096)
		(mid 331.538616 -58.788046)
		(end 331.475588 -59.022996)
		(width 0.127)
		(layer "In11.Cu")
		(net "FM_BOARD_SKU_ID4")
	)
	(arc
		(start 331.465682 -57.161176)
		(mid 331.412552 -57.388524)
		(end 331.475588 -57.613296)
		(width 0.127)
		(layer "In11.Cu")
		(net "FM_BOARD_SKU_ID4")
	)
	(arc
		(start 331.475588 -59.022996)
		(mid 331.41256 -59.257946)
		(end 331.475588 -59.492896)
		(width 0.127)
		(layer "In11.Cu")
		(net "FM_BOARD_SKU_ID4")
	)
	(arc
		(start 331.473048 -51.034696)
		(mid 331.535918 -51.2595)
		(end 331.482954 -51.486816)
		(width 0.127)
		(layer "In11.Cu")
		(net "FM_BOARD_SKU_ID4")
	)
	(arc
		(start 331.47508 -55.263796)
		(mid 331.412108 -55.4886)
		(end 331.465174 -55.715916)
		(width 0.127)
		(layer "In11.Cu")
		(net "FM_BOARD_SKU_ID4")
	)
	(arc
		(start 331.473048 -50.564796)
		(mid 331.41019 -50.799746)
		(end 331.473048 -51.034696)
		(width 0.127)
		(layer "In11.Cu")
		(net "FM_BOARD_SKU_ID4")
	)
	(arc
		(start 331.493114 -52.007516)
		(mid 331.538114 -52.228107)
		(end 331.475588 -52.444396)
		(width 0.127)
		(layer "In11.Cu")
		(net "FM_BOARD_SKU_ID4")
	)
	(segment
		(start 299.42028 -54.400196)
		(end 299.42028 -53.384196)
		(width 0.12954)
		(layer "F.Cu")
		(net "FM_BOARD_SKU_ID3")
	)
	(segment
		(start 330.79436 -52.679346)
		(end 330.252578 -52.679346)
		(width 0.12954)
		(layer "F.Cu")
		(net "FM_BOARD_SKU_ID3")
	)
	(segment
		(start 299.744892 -53.384196)
		(end 299.42028 -53.384196)
		(width 0.12954)
		(layer "F.Cu")
		(net "FM_BOARD_SKU_ID3")
	)
	(segment
		(start 300.09338 -53.035708)
		(end 299.744892 -53.384196)
		(width 0.12954)
		(layer "F.Cu")
		(net "FM_BOARD_SKU_ID3")
	)
	(via
		(at 300.09338 -53.035708)
		(size 0.508)
		(drill 0.254)
		(layers "F.Cu" "B.Cu")
		(net "FM_BOARD_SKU_ID3")
	)
	(via
		(at 330.252578 -52.679346)
		(size 0.4572)
		(drill 0.2032)
		(layers "F.Cu" "B.Cu")
		(net "FM_BOARD_SKU_ID3")
	)
	(segment
		(start 308.65826 -53.304948)
		(end 300.36262 -53.304948)
		(width 0.127)
		(layer "In6.Cu")
		(net "FM_BOARD_SKU_ID3")
	)
	(segment
		(start 313.779408 -52.78882)
		(end 309.174388 -52.78882)
		(width 0.127)
		(layer "In6.Cu")
		(net "FM_BOARD_SKU_ID3")
	)
	(segment
		(start 330.252578 -52.679346)
		(end 329.128882 -52.679346)
		(width 0.127)
		(layer "In6.Cu")
		(net "FM_BOARD_SKU_ID3")
	)
	(segment
		(start 328.98588 -52.822348)
		(end 328.42708 -52.822348)
		(width 0.127)
		(layer "In6.Cu")
		(net "FM_BOARD_SKU_ID3")
	)
	(segment
		(start 317.42888 -51.653948)
		(end 316.33668 -52.746148)
		(width 0.127)
		(layer "In6.Cu")
		(net "FM_BOARD_SKU_ID3")
	)
	(segment
		(start 327.725532 -52.1208)
		(end 324.52691 -52.1208)
		(width 0.127)
		(layer "In6.Cu")
		(net "FM_BOARD_SKU_ID3")
	)
	(segment
		(start 316.33668 -52.746148)
		(end 313.82208 -52.746148)
		(width 0.127)
		(layer "In6.Cu")
		(net "FM_BOARD_SKU_ID3")
	)
	(segment
		(start 324.084696 -51.678586)
		(end 322.828158 -51.678586)
		(width 0.127)
		(layer "In6.Cu")
		(net "FM_BOARD_SKU_ID3")
	)
	(segment
		(start 309.174388 -52.78882)
		(end 308.65826 -53.304948)
		(width 0.127)
		(layer "In6.Cu")
		(net "FM_BOARD_SKU_ID3")
	)
	(segment
		(start 328.42708 -52.822348)
		(end 327.725532 -52.1208)
		(width 0.127)
		(layer "In6.Cu")
		(net "FM_BOARD_SKU_ID3")
	)
	(segment
		(start 300.36262 -53.304948)
		(end 300.09338 -53.035708)
		(width 0.127)
		(layer "In6.Cu")
		(net "FM_BOARD_SKU_ID3")
	)
	(segment
		(start 329.128882 -52.679346)
		(end 328.98588 -52.822348)
		(width 0.127)
		(layer "In6.Cu")
		(net "FM_BOARD_SKU_ID3")
	)
	(segment
		(start 324.52691 -52.1208)
		(end 324.084696 -51.678586)
		(width 0.127)
		(layer "In6.Cu")
		(net "FM_BOARD_SKU_ID3")
	)
	(segment
		(start 318.69888 -51.653948)
		(end 317.42888 -51.653948)
		(width 0.127)
		(layer "In6.Cu")
		(net "FM_BOARD_SKU_ID3")
	)
	(segment
		(start 321.91452 -50.764948)
		(end 319.58788 -50.764948)
		(width 0.127)
		(layer "In6.Cu")
		(net "FM_BOARD_SKU_ID3")
	)
	(segment
		(start 322.828158 -51.678586)
		(end 321.91452 -50.764948)
		(width 0.127)
		(layer "In6.Cu")
		(net "FM_BOARD_SKU_ID3")
	)
	(segment
		(start 319.58788 -50.764948)
		(end 318.69888 -51.653948)
		(width 0.127)
		(layer "In6.Cu")
		(net "FM_BOARD_SKU_ID3")
	)
	(segment
		(start 313.82208 -52.746148)
		(end 313.779408 -52.78882)
		(width 0.127)
		(layer "In6.Cu")
		(net "FM_BOARD_SKU_ID3")
	)
	(segment
		(start 300.097952 -56.432196)
		(end 299.42028 -56.432196)
		(width 0.12954)
		(layer "F.Cu")
		(net "FM_BOARD_SKU_ID2")
	)
	(segment
		(start 330.252578 -51.739546)
		(end 330.25207 -51.738784)
		(width 0.12954)
		(layer "F.Cu")
		(net "FM_BOARD_SKU_ID2")
	)
	(segment
		(start 300.101 -56.429148)
		(end 300.097952 -56.432196)
		(width 0.12954)
		(layer "F.Cu")
		(net "FM_BOARD_SKU_ID2")
	)
	(segment
		(start 329.980798 -51.269646)
		(end 329.980036 -51.269646)
		(width 0.12954)
		(layer "F.Cu")
		(net "FM_BOARD_SKU_ID2")
	)
	(segment
		(start 299.42028 -56.432196)
		(end 299.42028 -55.416196)
		(width 0.12954)
		(layer "F.Cu")
		(net "FM_BOARD_SKU_ID2")
	)
	(segment
		(start 330.25207 -51.738784)
		(end 329.980798 -51.269646)
		(width 0.12954)
		(layer "F.Cu")
		(net "FM_BOARD_SKU_ID2")
	)
	(via
		(at 330.252578 -51.739546)
		(size 0.4572)
		(drill 0.2032)
		(layers "F.Cu" "B.Cu")
		(net "FM_BOARD_SKU_ID2")
	)
	(via
		(at 300.101 -56.429148)
		(size 0.508)
		(drill 0.254)
		(layers "F.Cu" "B.Cu")
		(net "FM_BOARD_SKU_ID2")
	)
	(segment
		(start 322.987924 -51.809142)
		(end 330.182982 -51.809142)
		(width 0.127)
		(layer "In13.Cu")
		(net "FM_BOARD_SKU_ID2")
	)
	(segment
		(start 301.135034 -54.760368)
		(end 305.326034 -54.760368)
		(width 0.127)
		(layer "In13.Cu")
		(net "FM_BOARD_SKU_ID2")
	)
	(segment
		(start 300.101 -56.429148)
		(end 301.0154 -55.514748)
		(width 0.127)
		(layer "In13.Cu")
		(net "FM_BOARD_SKU_ID2")
	)
	(segment
		(start 309.892446 -50.193956)
		(end 311.292494 -50.193956)
		(width 0.127)
		(layer "In13.Cu")
		(net "FM_BOARD_SKU_ID2")
	)
	(segment
		(start 312.175652 -49.310798)
		(end 320.48958 -49.310798)
		(width 0.127)
		(layer "In13.Cu")
		(net "FM_BOARD_SKU_ID2")
	)
	(segment
		(start 320.48958 -49.310798)
		(end 322.987924 -51.809142)
		(width 0.127)
		(layer "In13.Cu")
		(net "FM_BOARD_SKU_ID2")
	)
	(segment
		(start 305.326034 -54.760368)
		(end 309.892446 -50.193956)
		(width 0.127)
		(layer "In13.Cu")
		(net "FM_BOARD_SKU_ID2")
	)
	(segment
		(start 301.0154 -54.880002)
		(end 301.135034 -54.760368)
		(width 0.127)
		(layer "In13.Cu")
		(net "FM_BOARD_SKU_ID2")
	)
	(segment
		(start 330.182982 -51.809142)
		(end 330.252578 -51.739546)
		(width 0.127)
		(layer "In13.Cu")
		(net "FM_BOARD_SKU_ID2")
	)
	(segment
		(start 311.292494 -50.193956)
		(end 312.175652 -49.310798)
		(width 0.127)
		(layer "In13.Cu")
		(net "FM_BOARD_SKU_ID2")
	)
	(segment
		(start 301.0154 -55.514748)
		(end 301.0154 -54.880002)
		(width 0.127)
		(layer "In13.Cu")
		(net "FM_BOARD_SKU_ID2")
	)
	(segment
		(start 300.744128 -47.996348)
		(end 299.42028 -49.320196)
		(width 0.12954)
		(layer "F.Cu")
		(net "FM_BOARD_SKU_ID1")
	)
	(segment
		(start 329.165966 -50.799746)
		(end 329.437746 -50.329846)
		(width 0.12954)
		(layer "F.Cu")
		(net "FM_BOARD_SKU_ID1")
	)
	(segment
		(start 300.86554 -47.996348)
		(end 300.744128 -47.996348)
		(width 0.12954)
		(layer "F.Cu")
		(net "FM_BOARD_SKU_ID1")
	)
	(segment
		(start 299.42028 -50.336196)
		(end 299.42028 -49.320196)
		(width 0.12954)
		(layer "F.Cu")
		(net "FM_BOARD_SKU_ID1")
	)
	(via
		(at 329.437746 -50.329846)
		(size 0.4572)
		(drill 0.2032)
		(layers "F.Cu" "B.Cu")
		(net "FM_BOARD_SKU_ID1")
	)
	(via
		(at 323.975222 -49.266348)
		(size 0.508)
		(drill 0.254)
		(layers "F.Cu" "B.Cu")
		(net "FM_BOARD_SKU_ID1")
	)
	(via
		(at 327.846436 -50.576988)
		(size 0.6604)
		(drill 0.3302)
		(layers "F.Cu" "B.Cu")
		(net "FM_BOARD_SKU_ID1")
	)
	(via
		(at 300.86554 -47.996348)
		(size 0.762)
		(drill 0.254)
		(layers "F.Cu" "B.Cu")
		(net "FM_BOARD_SKU_ID1")
	)
	(segment
		(start 329.437746 -50.329846)
		(end 329.437746 -50.743358)
		(width 0.12954)
		(layer "B.Cu")
		(net "FM_BOARD_SKU_ID1")
	)
	(segment
		(start 329.437746 -50.743358)
		(end 329.329796 -50.851308)
		(width 0.12954)
		(layer "B.Cu")
		(net "FM_BOARD_SKU_ID1")
	)
	(segment
		(start 329.329796 -50.851308)
		(end 328.120756 -50.851308)
		(width 0.12954)
		(layer "B.Cu")
		(net "FM_BOARD_SKU_ID1")
	)
	(segment
		(start 324.407022 -49.698148)
		(end 323.975222 -49.266348)
		(width 0.12954)
		(layer "B.Cu")
		(net "FM_BOARD_SKU_ID1")
	)
	(segment
		(start 327.846436 -50.576988)
		(end 325.57212 -50.576988)
		(width 0.12954)
		(layer "B.Cu")
		(net "FM_BOARD_SKU_ID1")
	)
	(segment
		(start 324.69328 -49.698148)
		(end 324.407022 -49.698148)
		(width 0.12954)
		(layer "B.Cu")
		(net "FM_BOARD_SKU_ID1")
	)
	(segment
		(start 328.120756 -50.851308)
		(end 327.846436 -50.576988)
		(width 0.12954)
		(layer "B.Cu")
		(net "FM_BOARD_SKU_ID1")
	)
	(segment
		(start 325.57212 -50.576988)
		(end 324.69328 -49.698148)
		(width 0.12954)
		(layer "B.Cu")
		(net "FM_BOARD_SKU_ID1")
	)
	(segment
		(start 323.77888 -49.494948)
		(end 311.96788 -49.494948)
		(width 0.127)
		(layer "In6.Cu")
		(net "FM_BOARD_SKU_ID1")
	)
	(segment
		(start 302.189388 -49.320196)
		(end 300.86554 -47.996348)
		(width 0.127)
		(layer "In6.Cu")
		(net "FM_BOARD_SKU_ID1")
	)
	(segment
		(start 304.903632 -49.320196)
		(end 302.189388 -49.320196)
		(width 0.127)
		(layer "In6.Cu")
		(net "FM_BOARD_SKU_ID1")
	)
	(segment
		(start 311.96788 -49.494948)
		(end 311.71388 -49.748948)
		(width 0.127)
		(layer "In6.Cu")
		(net "FM_BOARD_SKU_ID1")
	)
	(segment
		(start 311.71388 -49.748948)
		(end 310.31688 -49.748948)
		(width 0.127)
		(layer "In6.Cu")
		(net "FM_BOARD_SKU_ID1")
	)
	(segment
		(start 323.975222 -49.298606)
		(end 323.77888 -49.494948)
		(width 0.127)
		(layer "In6.Cu")
		(net "FM_BOARD_SKU_ID1")
	)
	(segment
		(start 309.55488 -48.986948)
		(end 305.23688 -48.986948)
		(width 0.127)
		(layer "In6.Cu")
		(net "FM_BOARD_SKU_ID1")
	)
	(segment
		(start 323.975222 -49.266348)
		(end 323.975222 -49.298606)
		(width 0.127)
		(layer "In6.Cu")
		(net "FM_BOARD_SKU_ID1")
	)
	(segment
		(start 310.31688 -49.748948)
		(end 309.55488 -48.986948)
		(width 0.127)
		(layer "In6.Cu")
		(net "FM_BOARD_SKU_ID1")
	)
	(segment
		(start 305.23688 -48.986948)
		(end 304.903632 -49.320196)
		(width 0.127)
		(layer "In6.Cu")
		(net "FM_BOARD_SKU_ID1")
	)
	(segment
		(start 318.8081 -76.185014)
		(end 317.7921 -76.185014)
		(width 0.12954)
		(layer "F.Cu")
		(net "FM_BOARD_SKU_ID0")
	)
	(segment
		(start 318.8081 -75.205844)
		(end 318.8081 -76.185014)
		(width 0.12954)
		(layer "F.Cu")
		(net "FM_BOARD_SKU_ID0")
	)
	(segment
		(start 331.065378 -49.390046)
		(end 330.92136 -49.390046)
		(width 0.12954)
		(layer "F.Cu")
		(net "FM_BOARD_SKU_ID0")
	)
	(segment
		(start 319.5955 -74.418444)
		(end 318.8081 -75.205844)
		(width 0.12954)
		(layer "F.Cu")
		(net "FM_BOARD_SKU_ID0")
	)
	(segment
		(start 330.79436 -49.517046)
		(end 330.79436 -49.859946)
		(width 0.12954)
		(layer "F.Cu")
		(net "FM_BOARD_SKU_ID0")
	)
	(segment
		(start 330.92136 -49.390046)
		(end 330.79436 -49.517046)
		(width 0.12954)
		(layer "F.Cu")
		(net "FM_BOARD_SKU_ID0")
	)
	(via
		(at 319.5955 -74.418444)
		(size 0.508)
		(drill 0.254)
		(layers "F.Cu" "B.Cu")
		(net "FM_BOARD_SKU_ID0")
	)
	(via
		(at 331.065378 -49.390046)
		(size 0.4572)
		(drill 0.2032)
		(layers "F.Cu" "B.Cu")
		(net "FM_BOARD_SKU_ID0")
	)
	(segment
		(start 329.18908 -65.827148)
		(end 325.68388 -69.332348)
		(width 0.127)
		(layer "In11.Cu")
		(net "FM_BOARD_SKU_ID0")
	)
	(segment
		(start 330.25588 -55.968646)
		(end 328.252582 -55.968646)
		(width 0.127)
		(layer "In11.Cu")
		(net "FM_BOARD_SKU_ID0")
	)
	(segment
		(start 330.670662 -53.836316)
		(end 330.660248 -53.854096)
		(width 0.127)
		(layer "In11.Cu")
		(net "FM_BOARD_SKU_ID0")
	)
	(segment
		(start 330.658978 -51.504596)
		(end 330.675234 -51.532536)
		(width 0.127)
		(layer "In11.Cu")
		(net "FM_BOARD_SKU_ID0")
	)
	(segment
		(start 319.753996 -74.259948)
		(end 319.5955 -74.418444)
		(width 0.127)
		(layer "In11.Cu")
		(net "FM_BOARD_SKU_ID0")
	)
	(segment
		(start 325.68388 -70.094348)
		(end 321.51828 -74.259948)
		(width 0.127)
		(layer "In11.Cu")
		(net "FM_BOARD_SKU_ID0")
	)
	(segment
		(start 330.661772 -55.263796)
		(end 330.674472 -55.285386)
		(width 0.127)
		(layer "In11.Cu")
		(net "FM_BOARD_SKU_ID0")
	)
	(segment
		(start 328.09688 -56.124348)
		(end 328.09688 -58.562748)
		(width 0.127)
		(layer "In11.Cu")
		(net "FM_BOARD_SKU_ID0")
	)
	(segment
		(start 331.065378 -49.390046)
		(end 330.658978 -50.094896)
		(width 0.127)
		(layer "In11.Cu")
		(net "FM_BOARD_SKU_ID0")
	)
	(segment
		(start 330.643992 -55.233062)
		(end 330.661772 -55.263796)
		(width 0.127)
		(layer "In11.Cu")
		(net "FM_BOARD_SKU_ID0")
	)
	(segment
		(start 328.09688 -58.562748)
		(end 329.18908 -59.654948)
		(width 0.127)
		(layer "In11.Cu")
		(net "FM_BOARD_SKU_ID0")
	)
	(segment
		(start 330.660248 -52.444396)
		(end 330.670662 -52.462176)
		(width 0.127)
		(layer "In11.Cu")
		(net "FM_BOARD_SKU_ID0")
	)
	(segment
		(start 321.51828 -74.259948)
		(end 319.753996 -74.259948)
		(width 0.127)
		(layer "In11.Cu")
		(net "FM_BOARD_SKU_ID0")
	)
	(segment
		(start 325.68388 -69.332348)
		(end 325.68388 -70.094348)
		(width 0.127)
		(layer "In11.Cu")
		(net "FM_BOARD_SKU_ID0")
	)
	(segment
		(start 329.18908 -59.654948)
		(end 329.18908 -65.827148)
		(width 0.127)
		(layer "In11.Cu")
		(net "FM_BOARD_SKU_ID0")
	)
	(segment
		(start 328.252582 -55.968646)
		(end 328.09688 -56.124348)
		(width 0.127)
		(layer "In11.Cu")
		(net "FM_BOARD_SKU_ID0")
	)
	(segment
		(start 330.662534 -55.733696)
		(end 330.65466 -55.747158)
		(width 0.127)
		(layer "In11.Cu")
		(net "FM_BOARD_SKU_ID0")
	)
	(arc
		(start 330.660756 -52.914296)
		(mid 330.598 -53.149246)
		(end 330.660756 -53.384196)
		(width 0.127)
		(layer "In11.Cu")
		(net "FM_BOARD_SKU_ID0")
	)
	(arc
		(start 330.675234 -51.532536)
		(mid 330.722939 -51.7554)
		(end 330.660248 -51.974496)
		(width 0.127)
		(layer "In11.Cu")
		(net "FM_BOARD_SKU_ID0")
	)
	(arc
		(start 330.658978 -50.094896)
		(mid 330.59595 -50.329846)
		(end 330.658978 -50.564796)
		(width 0.127)
		(layer "In11.Cu")
		(net "FM_BOARD_SKU_ID0")
	)
	(arc
		(start 330.660248 -51.974496)
		(mid 330.597356 -52.209446)
		(end 330.660248 -52.444396)
		(width 0.127)
		(layer "In11.Cu")
		(net "FM_BOARD_SKU_ID0")
	)
	(arc
		(start 330.65466 -55.747158)
		(mid 330.483971 -55.909588)
		(end 330.25588 -55.968646)
		(width 0.127)
		(layer "In11.Cu")
		(net "FM_BOARD_SKU_ID0")
	)
	(arc
		(start 330.660248 -54.323996)
		(mid 330.723106 -54.558946)
		(end 330.660248 -54.793896)
		(width 0.127)
		(layer "In11.Cu")
		(net "FM_BOARD_SKU_ID0")
	)
	(arc
		(start 330.660756 -53.384196)
		(mid 330.723558 -53.609)
		(end 330.670662 -53.836316)
		(width 0.127)
		(layer "In11.Cu")
		(net "FM_BOARD_SKU_ID0")
	)
	(arc
		(start 330.670662 -52.462176)
		(mid 330.723469 -52.68949)
		(end 330.660756 -52.914296)
		(width 0.127)
		(layer "In11.Cu")
		(net "FM_BOARD_SKU_ID0")
	)
	(arc
		(start 330.658978 -50.564796)
		(mid 330.722006 -50.799746)
		(end 330.658978 -51.034696)
		(width 0.127)
		(layer "In11.Cu")
		(net "FM_BOARD_SKU_ID0")
	)
	(arc
		(start 330.674472 -55.285386)
		(mid 330.725428 -55.511049)
		(end 330.662534 -55.733696)
		(width 0.127)
		(layer "In11.Cu")
		(net "FM_BOARD_SKU_ID0")
	)
	(arc
		(start 330.660248 -53.854096)
		(mid 330.59739 -54.089046)
		(end 330.660248 -54.323996)
		(width 0.127)
		(layer "In11.Cu")
		(net "FM_BOARD_SKU_ID0")
	)
	(arc
		(start 330.660248 -54.793896)
		(mid 330.597712 -55.011462)
		(end 330.643992 -55.233062)
		(width 0.127)
		(layer "In11.Cu")
		(net "FM_BOARD_SKU_ID0")
	)
	(arc
		(start 330.658978 -51.034696)
		(mid 330.59595 -51.269646)
		(end 330.658978 -51.504596)
		(width 0.127)
		(layer "In11.Cu")
		(net "FM_BOARD_SKU_ID0")
	)
	(segment
		(start 157.68193 -108.295948)
		(end 158.29788 -108.295948)
		(width 0.12954)
		(layer "F.Cu")
		(net "FM_BMC_SUSACK_R_N")
	)
	(segment
		(start 171.755562 -108.175552)
		(end 171.355512 -107.775502)
		(width 0.12954)
		(layer "F.Cu")
		(net "FM_BMC_SUSACK_R_N")
	)
	(via
		(at 158.29788 -108.295948)
		(size 0.508)
		(drill 0.254)
		(layers "F.Cu" "B.Cu")
		(net "FM_BMC_SUSACK_R_N")
	)
	(via
		(at 171.355512 -107.775502)
		(size 0.4572)
		(drill 0.254)
		(layers "F.Cu" "B.Cu")
		(net "FM_BMC_SUSACK_R_N")
	)
	(segment
		(start 160.116266 -107.775502)
		(end 158.818326 -107.775502)
		(width 0.127)
		(layer "In6.Cu")
		(net "FM_BMC_SUSACK_R_N")
	)
	(segment
		(start 163.303458 -106.495088)
		(end 162.937698 -106.860848)
		(width 0.127)
		(layer "In6.Cu")
		(net "FM_BMC_SUSACK_R_N")
	)
	(segment
		(start 158.818326 -107.775502)
		(end 158.29788 -108.295948)
		(width 0.127)
		(layer "In6.Cu")
		(net "FM_BMC_SUSACK_R_N")
	)
	(segment
		(start 161.39668 -106.495088)
		(end 160.116266 -107.775502)
		(width 0.127)
		(layer "In6.Cu")
		(net "FM_BMC_SUSACK_R_N")
	)
	(segment
		(start 162.548062 -106.860848)
		(end 162.182302 -106.495088)
		(width 0.127)
		(layer "In6.Cu")
		(net "FM_BMC_SUSACK_R_N")
	)
	(segment
		(start 162.182302 -106.495088)
		(end 161.39668 -106.495088)
		(width 0.127)
		(layer "In6.Cu")
		(net "FM_BMC_SUSACK_R_N")
	)
	(segment
		(start 162.937698 -106.860848)
		(end 162.548062 -106.860848)
		(width 0.127)
		(layer "In6.Cu")
		(net "FM_BMC_SUSACK_R_N")
	)
	(segment
		(start 171.355512 -107.775502)
		(end 168.252902 -107.775502)
		(width 0.127)
		(layer "In6.Cu")
		(net "FM_BMC_SUSACK_R_N")
	)
	(segment
		(start 168.252902 -107.775502)
		(end 166.972488 -106.495088)
		(width 0.127)
		(layer "In6.Cu")
		(net "FM_BMC_SUSACK_R_N")
	)
	(segment
		(start 166.972488 -106.495088)
		(end 163.303458 -106.495088)
		(width 0.127)
		(layer "In6.Cu")
		(net "FM_BMC_SUSACK_R_N")
	)
	(segment
		(start 182.955692 -111.375444)
		(end 183.355742 -110.975394)
		(width 0.12954)
		(layer "F.Cu")
		(net "FM_BMC_RSTBTN_OUT_N")
	)
	(via
		(at 307.57114 -32.893508)
		(size 0.508)
		(drill 0.254)
		(layers "F.Cu" "B.Cu")
		(net "FM_BMC_RSTBTN_OUT_N")
	)
	(via
		(at 183.355742 -110.975394)
		(size 0.4572)
		(drill 0.254)
		(layers "F.Cu" "B.Cu")
		(net "FM_BMC_RSTBTN_OUT_N")
	)
	(via
		(at 321.87388 -114.645948)
		(size 0.508)
		(drill 0.254)
		(layers "F.Cu" "B.Cu")
		(net "FM_BMC_RSTBTN_OUT_N")
	)
	(segment
		(start 309.875428 -31.269178)
		(end 310.055006 -31.0896)
		(width 0.12954)
		(layer "B.Cu")
		(net "FM_BMC_RSTBTN_OUT_N")
	)
	(segment
		(start 315.717682 -36.831016)
		(end 315.976 -37.089334)
		(width 0.12954)
		(layer "B.Cu")
		(net "FM_BMC_RSTBTN_OUT_N")
	)
	(segment
		(start 307.57114 -32.708088)
		(end 309.01005 -31.269178)
		(width 0.12954)
		(layer "B.Cu")
		(net "FM_BMC_RSTBTN_OUT_N")
	)
	(segment
		(start 310.055006 -31.0896)
		(end 312.547762 -31.0896)
		(width 0.12954)
		(layer "B.Cu")
		(net "FM_BMC_RSTBTN_OUT_N")
	)
	(segment
		(start 307.57114 -32.893508)
		(end 307.57114 -32.708088)
		(width 0.12954)
		(layer "B.Cu")
		(net "FM_BMC_RSTBTN_OUT_N")
	)
	(segment
		(start 315.717682 -34.25952)
		(end 315.717682 -36.831016)
		(width 0.12954)
		(layer "B.Cu")
		(net "FM_BMC_RSTBTN_OUT_N")
	)
	(segment
		(start 309.01005 -31.269178)
		(end 309.875428 -31.269178)
		(width 0.12954)
		(layer "B.Cu")
		(net "FM_BMC_RSTBTN_OUT_N")
	)
	(segment
		(start 312.547762 -31.0896)
		(end 315.717682 -34.25952)
		(width 0.12954)
		(layer "B.Cu")
		(net "FM_BMC_RSTBTN_OUT_N")
	)
	(segment
		(start 315.976 -37.57803)
		(end 317.473076 -39.075106)
		(width 0.12954)
		(layer "B.Cu")
		(net "FM_BMC_RSTBTN_OUT_N")
	)
	(segment
		(start 315.976 -37.089334)
		(end 315.976 -37.57803)
		(width 0.12954)
		(layer "B.Cu")
		(net "FM_BMC_RSTBTN_OUT_N")
	)
	(segment
		(start 307.1114 -43.480228)
		(end 307.1114 -33.353248)
		(width 0.127)
		(layer "In2.Cu")
		(net "FM_BMC_RSTBTN_OUT_N")
	)
	(segment
		(start 315.70295 -77.050646)
		(end 311.36844 -66.586608)
		(width 0.127)
		(layer "In2.Cu")
		(net "FM_BMC_RSTBTN_OUT_N")
	)
	(segment
		(start 311.36844 -58.714132)
		(end 307.70068 -55.046372)
		(width 0.127)
		(layer "In2.Cu")
		(net "FM_BMC_RSTBTN_OUT_N")
	)
	(segment
		(start 321.87388 -114.645948)
		(end 321.23888 -114.010948)
		(width 0.127)
		(layer "In2.Cu")
		(net "FM_BMC_RSTBTN_OUT_N")
	)
	(segment
		(start 307.1114 -33.353248)
		(end 307.57114 -32.893508)
		(width 0.127)
		(layer "In2.Cu")
		(net "FM_BMC_RSTBTN_OUT_N")
	)
	(segment
		(start 321.23888 -114.010948)
		(end 321.23888 -82.586576)
		(width 0.127)
		(layer "In2.Cu")
		(net "FM_BMC_RSTBTN_OUT_N")
	)
	(segment
		(start 311.36844 -66.586608)
		(end 311.36844 -58.714132)
		(width 0.127)
		(layer "In2.Cu")
		(net "FM_BMC_RSTBTN_OUT_N")
	)
	(segment
		(start 321.23888 -82.586576)
		(end 315.70295 -77.050646)
		(width 0.127)
		(layer "In2.Cu")
		(net "FM_BMC_RSTBTN_OUT_N")
	)
	(segment
		(start 307.70068 -55.046372)
		(end 307.70068 -44.069508)
		(width 0.127)
		(layer "In2.Cu")
		(net "FM_BMC_RSTBTN_OUT_N")
	)
	(segment
		(start 307.70068 -44.069508)
		(end 307.1114 -43.480228)
		(width 0.127)
		(layer "In2.Cu")
		(net "FM_BMC_RSTBTN_OUT_N")
	)
	(segment
		(start 198.51878 -110.376208)
		(end 198.26224 -110.119668)
		(width 0.127)
		(layer "In15.Cu")
		(net "FM_BMC_RSTBTN_OUT_N")
	)
	(segment
		(start 211.455 -106.934)
		(end 208.637124 -109.751876)
		(width 0.127)
		(layer "In15.Cu")
		(net "FM_BMC_RSTBTN_OUT_N")
	)
	(segment
		(start 211.455 -106.375708)
		(end 211.455 -106.934)
		(width 0.127)
		(layer "In15.Cu")
		(net "FM_BMC_RSTBTN_OUT_N")
	)
	(segment
		(start 281.536648 -116.449348)
		(end 269.511526 -116.449348)
		(width 0.127)
		(layer "In15.Cu")
		(net "FM_BMC_RSTBTN_OUT_N")
	)
	(segment
		(start 284.046168 -113.939828)
		(end 281.536648 -116.449348)
		(width 0.127)
		(layer "In15.Cu")
		(net "FM_BMC_RSTBTN_OUT_N")
	)
	(segment
		(start 217.592402 -107.203748)
		(end 216.154762 -105.766108)
		(width 0.127)
		(layer "In15.Cu")
		(net "FM_BMC_RSTBTN_OUT_N")
	)
	(segment
		(start 267.822426 -118.138448)
		(end 249.92584 -118.138448)
		(width 0.127)
		(layer "In15.Cu")
		(net "FM_BMC_RSTBTN_OUT_N")
	)
	(segment
		(start 198.26224 -110.119668)
		(end 191.87922 -110.119668)
		(width 0.127)
		(layer "In15.Cu")
		(net "FM_BMC_RSTBTN_OUT_N")
	)
	(segment
		(start 199.93864 -110.376208)
		(end 198.51878 -110.376208)
		(width 0.127)
		(layer "In15.Cu")
		(net "FM_BMC_RSTBTN_OUT_N")
	)
	(segment
		(start 321.87388 -114.645948)
		(end 321.16776 -113.939828)
		(width 0.127)
		(layer "In15.Cu")
		(net "FM_BMC_RSTBTN_OUT_N")
	)
	(segment
		(start 201.373232 -109.916468)
		(end 200.39838 -109.916468)
		(width 0.127)
		(layer "In15.Cu")
		(net "FM_BMC_RSTBTN_OUT_N")
	)
	(segment
		(start 184.76976 -112.169448)
		(end 184.55386 -111.953548)
		(width 0.127)
		(layer "In15.Cu")
		(net "FM_BMC_RSTBTN_OUT_N")
	)
	(segment
		(start 183.757316 -111.376968)
		(end 183.355742 -110.975394)
		(width 0.127)
		(layer "In15.Cu")
		(net "FM_BMC_RSTBTN_OUT_N")
	)
	(segment
		(start 184.3532 -111.376968)
		(end 183.757316 -111.376968)
		(width 0.127)
		(layer "In15.Cu")
		(net "FM_BMC_RSTBTN_OUT_N")
	)
	(segment
		(start 208.637124 -109.751876)
		(end 206.246222 -109.751876)
		(width 0.127)
		(layer "In15.Cu")
		(net "FM_BMC_RSTBTN_OUT_N")
	)
	(segment
		(start 269.511526 -116.449348)
		(end 267.822426 -118.138448)
		(width 0.127)
		(layer "In15.Cu")
		(net "FM_BMC_RSTBTN_OUT_N")
	)
	(segment
		(start 187.11672 -112.169448)
		(end 184.76976 -112.169448)
		(width 0.127)
		(layer "In15.Cu")
		(net "FM_BMC_RSTBTN_OUT_N")
	)
	(segment
		(start 184.55386 -111.953548)
		(end 184.55386 -111.577628)
		(width 0.127)
		(layer "In15.Cu")
		(net "FM_BMC_RSTBTN_OUT_N")
	)
	(segment
		(start 202.119992 -110.663228)
		(end 201.373232 -109.916468)
		(width 0.127)
		(layer "In15.Cu")
		(net "FM_BMC_RSTBTN_OUT_N")
	)
	(segment
		(start 246.03964 -114.252248)
		(end 240.073434 -114.252248)
		(width 0.127)
		(layer "In15.Cu")
		(net "FM_BMC_RSTBTN_OUT_N")
	)
	(segment
		(start 233.024934 -107.203748)
		(end 217.592402 -107.203748)
		(width 0.127)
		(layer "In15.Cu")
		(net "FM_BMC_RSTBTN_OUT_N")
	)
	(segment
		(start 240.073434 -114.252248)
		(end 233.024934 -107.203748)
		(width 0.127)
		(layer "In15.Cu")
		(net "FM_BMC_RSTBTN_OUT_N")
	)
	(segment
		(start 191.87922 -110.119668)
		(end 190.3476 -111.651288)
		(width 0.127)
		(layer "In15.Cu")
		(net "FM_BMC_RSTBTN_OUT_N")
	)
	(segment
		(start 190.3476 -111.651288)
		(end 187.63488 -111.651288)
		(width 0.127)
		(layer "In15.Cu")
		(net "FM_BMC_RSTBTN_OUT_N")
	)
	(segment
		(start 212.0646 -105.766108)
		(end 211.455 -106.375708)
		(width 0.127)
		(layer "In15.Cu")
		(net "FM_BMC_RSTBTN_OUT_N")
	)
	(segment
		(start 249.92584 -118.138448)
		(end 246.03964 -114.252248)
		(width 0.127)
		(layer "In15.Cu")
		(net "FM_BMC_RSTBTN_OUT_N")
	)
	(segment
		(start 216.154762 -105.766108)
		(end 212.0646 -105.766108)
		(width 0.127)
		(layer "In15.Cu")
		(net "FM_BMC_RSTBTN_OUT_N")
	)
	(segment
		(start 187.63488 -111.651288)
		(end 187.11672 -112.169448)
		(width 0.127)
		(layer "In15.Cu")
		(net "FM_BMC_RSTBTN_OUT_N")
	)
	(segment
		(start 205.33487 -110.663228)
		(end 202.119992 -110.663228)
		(width 0.127)
		(layer "In15.Cu")
		(net "FM_BMC_RSTBTN_OUT_N")
	)
	(segment
		(start 321.16776 -113.939828)
		(end 284.046168 -113.939828)
		(width 0.127)
		(layer "In15.Cu")
		(net "FM_BMC_RSTBTN_OUT_N")
	)
	(segment
		(start 206.246222 -109.751876)
		(end 205.33487 -110.663228)
		(width 0.127)
		(layer "In15.Cu")
		(net "FM_BMC_RSTBTN_OUT_N")
	)
	(segment
		(start 184.55386 -111.577628)
		(end 184.3532 -111.376968)
		(width 0.127)
		(layer "In15.Cu")
		(net "FM_BMC_RSTBTN_OUT_N")
	)
	(segment
		(start 200.39838 -109.916468)
		(end 199.93864 -110.376208)
		(width 0.127)
		(layer "In15.Cu")
		(net "FM_BMC_RSTBTN_OUT_N")
	)
	(segment
		(start 190.708534 -119.929148)
		(end 192.664334 -121.884948)
		(width 0.12954)
		(layer "F.Cu")
		(net "FM_BMC_READY_R_PLD_N")
	)
	(segment
		(start 190.55588 -119.929148)
		(end 190.708534 -119.929148)
		(width 0.12954)
		(layer "F.Cu")
		(net "FM_BMC_READY_R_PLD_N")
	)
	(segment
		(start 192.664334 -121.884948)
		(end 192.98031 -121.884948)
		(width 0.12954)
		(layer "F.Cu")
		(net "FM_BMC_READY_R_PLD_N")
	)
	(segment
		(start 186.155584 -117.775482)
		(end 186.57189 -118.191788)
		(width 0.12954)
		(layer "F.Cu")
		(net "FM_BMC_READY_R_PLD_N")
	)
	(segment
		(start 187.92698 -118.191788)
		(end 189.66434 -119.929148)
		(width 0.12954)
		(layer "F.Cu")
		(net "FM_BMC_READY_R_PLD_N")
	)
	(segment
		(start 186.57189 -118.191788)
		(end 187.92698 -118.191788)
		(width 0.12954)
		(layer "F.Cu")
		(net "FM_BMC_READY_R_PLD_N")
	)
	(segment
		(start 189.66434 -119.929148)
		(end 190.55588 -119.929148)
		(width 0.12954)
		(layer "F.Cu")
		(net "FM_BMC_READY_R_PLD_N")
	)
	(via
		(at 190.55588 -119.929148)
		(size 0.762)
		(drill 0.381)
		(layers "F.Cu" "B.Cu")
		(net "FM_BMC_READY_R_PLD_N")
	)
	(segment
		(start 333.398114 -38.050216)
		(end 333.398114 -34.966656)
		(width 0.0889)
		(layer "F.Cu")
		(net "FM_BMC_READY_R_N")
	)
	(segment
		(start 333.398114 -34.966656)
		(end 332.147418 -33.71596)
		(width 0.0889)
		(layer "F.Cu")
		(net "FM_BMC_READY_R_N")
	)
	(segment
		(start 332.147418 -30.50921)
		(end 332.039976 -30.401768)
		(width 0.12954)
		(layer "F.Cu")
		(net "FM_BMC_READY_R_N")
	)
	(segment
		(start 332.039976 -30.401768)
		(end 332.039976 -30.086808)
		(width 0.12954)
		(layer "F.Cu")
		(net "FM_BMC_READY_R_N")
	)
	(segment
		(start 332.147418 -30.681168)
		(end 332.147418 -30.50921)
		(width 0.12954)
		(layer "F.Cu")
		(net "FM_BMC_READY_R_N")
	)
	(segment
		(start 193.78041 -121.884948)
		(end 194.39001 -121.884948)
		(width 0.12954)
		(layer "F.Cu")
		(net "FM_BMC_READY_R_N")
	)
	(segment
		(start 332.147418 -33.71596)
		(end 332.147418 -30.681168)
		(width 0.0889)
		(layer "F.Cu")
		(net "FM_BMC_READY_R_N")
	)
	(via
		(at 332.039976 -30.086808)
		(size 0.508)
		(drill 0.254)
		(layers "F.Cu" "B.Cu")
		(net "FM_BMC_READY_R_N")
	)
	(via
		(at 328.78776 -121.225818)
		(size 0.508)
		(drill 0.254)
		(layers "F.Cu" "B.Cu")
		(net "FM_BMC_READY_R_N")
	)
	(via
		(at 194.39001 -121.884948)
		(size 0.508)
		(drill 0.254)
		(layers "F.Cu" "B.Cu")
		(net "FM_BMC_READY_R_N")
	)
	(segment
		(start 328.9173 -72.337168)
		(end 328.9173 -74.541888)
		(width 0.127)
		(layer "In2.Cu")
		(net "FM_BMC_READY_R_N")
	)
	(segment
		(start 331.422756 -36.989512)
		(end 328.11974 -40.292528)
		(width 0.127)
		(layer "In2.Cu")
		(net "FM_BMC_READY_R_N")
	)
	(segment
		(start 329.48626 -75.110848)
		(end 329.48626 -76.845668)
		(width 0.127)
		(layer "In2.Cu")
		(net "FM_BMC_READY_R_N")
	)
	(segment
		(start 332.039976 -30.086808)
		(end 331.422756 -30.704028)
		(width 0.127)
		(layer "In2.Cu")
		(net "FM_BMC_READY_R_N")
	)
	(segment
		(start 328.11974 -40.292528)
		(end 328.11974 -58.130948)
		(width 0.127)
		(layer "In2.Cu")
		(net "FM_BMC_READY_R_N")
	)
	(segment
		(start 329.692 -59.703208)
		(end 329.692 -71.562468)
		(width 0.127)
		(layer "In2.Cu")
		(net "FM_BMC_READY_R_N")
	)
	(segment
		(start 328.5363 -77.795628)
		(end 328.5363 -120.974358)
		(width 0.127)
		(layer "In2.Cu")
		(net "FM_BMC_READY_R_N")
	)
	(segment
		(start 331.422756 -30.704028)
		(end 331.422756 -36.989512)
		(width 0.127)
		(layer "In2.Cu")
		(net "FM_BMC_READY_R_N")
	)
	(segment
		(start 329.48626 -76.845668)
		(end 328.5363 -77.795628)
		(width 0.127)
		(layer "In2.Cu")
		(net "FM_BMC_READY_R_N")
	)
	(segment
		(start 328.9173 -74.541888)
		(end 329.48626 -75.110848)
		(width 0.127)
		(layer "In2.Cu")
		(net "FM_BMC_READY_R_N")
	)
	(segment
		(start 328.11974 -58.130948)
		(end 329.692 -59.703208)
		(width 0.127)
		(layer "In2.Cu")
		(net "FM_BMC_READY_R_N")
	)
	(segment
		(start 328.5363 -120.974358)
		(end 328.78776 -121.225818)
		(width 0.127)
		(layer "In2.Cu")
		(net "FM_BMC_READY_R_N")
	)
	(segment
		(start 329.692 -71.562468)
		(end 328.9173 -72.337168)
		(width 0.127)
		(layer "In2.Cu")
		(net "FM_BMC_READY_R_N")
	)
	(segment
		(start 243.11102 -121.059448)
		(end 245.91264 -123.861068)
		(width 0.127)
		(layer "In15.Cu")
		(net "FM_BMC_READY_R_N")
	)
	(segment
		(start 199.640952 -123.408948)
		(end 201.887328 -123.408948)
		(width 0.127)
		(layer "In15.Cu")
		(net "FM_BMC_READY_R_N")
	)
	(segment
		(start 327.11009 -119.548148)
		(end 328.78776 -121.225818)
		(width 0.127)
		(layer "In15.Cu")
		(net "FM_BMC_READY_R_N")
	)
	(segment
		(start 195.05422 -121.884948)
		(end 196.01942 -122.850148)
		(width 0.127)
		(layer "In15.Cu")
		(net "FM_BMC_READY_R_N")
	)
	(segment
		(start 215.061292 -122.555508)
		(end 219.473272 -118.143528)
		(width 0.127)
		(layer "In15.Cu")
		(net "FM_BMC_READY_R_N")
	)
	(segment
		(start 199.082152 -122.850148)
		(end 199.640952 -123.408948)
		(width 0.127)
		(layer "In15.Cu")
		(net "FM_BMC_READY_R_N")
	)
	(segment
		(start 281.665172 -122.024648)
		(end 284.141672 -119.548148)
		(width 0.127)
		(layer "In15.Cu")
		(net "FM_BMC_READY_R_N")
	)
	(segment
		(start 194.39001 -121.884948)
		(end 195.05422 -121.884948)
		(width 0.127)
		(layer "In15.Cu")
		(net "FM_BMC_READY_R_N")
	)
	(segment
		(start 196.01942 -122.850148)
		(end 199.082152 -122.850148)
		(width 0.127)
		(layer "In15.Cu")
		(net "FM_BMC_READY_R_N")
	)
	(segment
		(start 201.887328 -123.408948)
		(end 202.740768 -122.555508)
		(width 0.127)
		(layer "In15.Cu")
		(net "FM_BMC_READY_R_N")
	)
	(segment
		(start 284.141672 -119.548148)
		(end 327.11009 -119.548148)
		(width 0.127)
		(layer "In15.Cu")
		(net "FM_BMC_READY_R_N")
	)
	(segment
		(start 247.610884 -123.861068)
		(end 249.447304 -122.024648)
		(width 0.127)
		(layer "In15.Cu")
		(net "FM_BMC_READY_R_N")
	)
	(segment
		(start 232.12552 -118.143528)
		(end 235.04144 -121.059448)
		(width 0.127)
		(layer "In15.Cu")
		(net "FM_BMC_READY_R_N")
	)
	(segment
		(start 235.04144 -121.059448)
		(end 243.11102 -121.059448)
		(width 0.127)
		(layer "In15.Cu")
		(net "FM_BMC_READY_R_N")
	)
	(segment
		(start 249.447304 -122.024648)
		(end 281.665172 -122.024648)
		(width 0.127)
		(layer "In15.Cu")
		(net "FM_BMC_READY_R_N")
	)
	(segment
		(start 202.740768 -122.555508)
		(end 215.061292 -122.555508)
		(width 0.127)
		(layer "In15.Cu")
		(net "FM_BMC_READY_R_N")
	)
	(segment
		(start 245.91264 -123.861068)
		(end 247.610884 -123.861068)
		(width 0.127)
		(layer "In15.Cu")
		(net "FM_BMC_READY_R_N")
	)
	(segment
		(start 219.473272 -118.143528)
		(end 232.12552 -118.143528)
		(width 0.127)
		(layer "In15.Cu")
		(net "FM_BMC_READY_R_N")
	)
	(segment
		(start 143.547084 -12.19708)
		(end 143.556736 -12.187428)
		(width 0.12954)
		(layer "F.Cu")
		(net "FM_BMC_PWRBTN_OUT_R_N")
	)
	(segment
		(start 143.547084 -13.600176)
		(end 143.547084 -12.19708)
		(width 0.12954)
		(layer "F.Cu")
		(net "FM_BMC_PWRBTN_OUT_R_N")
	)
	(via
		(at 143.556736 -12.187428)
		(size 0.508)
		(drill 0.254)
		(layers "F.Cu" "B.Cu")
		(net "FM_BMC_PWRBTN_OUT_R_N")
	)
	(segment
		(start 143.556736 -12.187428)
		(end 143.556736 -12.832842)
		(width 0.12954)
		(layer "B.Cu")
		(net "FM_BMC_PWRBTN_OUT_R_N")
	)
	(segment
		(start 143.556736 -12.832842)
		(end 143.0274 -13.362178)
		(width 0.12954)
		(layer "B.Cu")
		(net "FM_BMC_PWRBTN_OUT_R_N")
	)
	(via
		(at 320.202814 -29.057346)
		(size 0.508)
		(drill 0.254)
		(layers "F.Cu" "B.Cu")
		(net "FM_BMC_PWRBTN_OUT_N")
	)
	(via
		(at 147.30222 -18.301208)
		(size 0.508)
		(drill 0.254)
		(layers "F.Cu" "B.Cu")
		(net "FM_BMC_PWRBTN_OUT_N")
	)
	(via
		(at 271.07388 -36.921948)
		(size 0.508)
		(drill 0.254)
		(layers "F.Cu" "B.Cu")
		(net "FM_BMC_PWRBTN_OUT_N")
	)
	(segment
		(start 145.978118 -18.301208)
		(end 143.0274 -15.35049)
		(width 0.12954)
		(layer "B.Cu")
		(net "FM_BMC_PWRBTN_OUT_N")
	)
	(segment
		(start 319.58153 -29.619956)
		(end 319.58153 -32.070548)
		(width 0.12954)
		(layer "B.Cu")
		(net "FM_BMC_PWRBTN_OUT_N")
	)
	(segment
		(start 320.14414 -29.057346)
		(end 319.58153 -29.619956)
		(width 0.12954)
		(layer "B.Cu")
		(net "FM_BMC_PWRBTN_OUT_N")
	)
	(segment
		(start 147.30222 -18.301208)
		(end 145.978118 -18.301208)
		(width 0.12954)
		(layer "B.Cu")
		(net "FM_BMC_PWRBTN_OUT_N")
	)
	(segment
		(start 143.0274 -15.35049)
		(end 143.0274 -14.162278)
		(width 0.12954)
		(layer "B.Cu")
		(net "FM_BMC_PWRBTN_OUT_N")
	)
	(segment
		(start 320.202814 -29.057346)
		(end 320.14414 -29.057346)
		(width 0.12954)
		(layer "B.Cu")
		(net "FM_BMC_PWRBTN_OUT_N")
	)
	(segment
		(start 310.261 -27.860498)
		(end 310.261 -30.120082)
		(width 0.127)
		(layer "In11.Cu")
		(net "FM_BMC_PWRBTN_OUT_N")
	)
	(segment
		(start 310.261 -30.120082)
		(end 308.615334 -31.765748)
		(width 0.127)
		(layer "In11.Cu")
		(net "FM_BMC_PWRBTN_OUT_N")
	)
	(segment
		(start 306.35575 -31.765748)
		(end 305.36388 -32.757618)
		(width 0.127)
		(layer "In11.Cu")
		(net "FM_BMC_PWRBTN_OUT_N")
	)
	(segment
		(start 304.14595 -37.353748)
		(end 271.50568 -37.353748)
		(width 0.127)
		(layer "In11.Cu")
		(net "FM_BMC_PWRBTN_OUT_N")
	)
	(segment
		(start 320.202814 -29.057346)
		(end 320.065146 -29.057346)
		(width 0.127)
		(layer "In11.Cu")
		(net "FM_BMC_PWRBTN_OUT_N")
	)
	(segment
		(start 305.36388 -36.135818)
		(end 304.14595 -37.353748)
		(width 0.127)
		(layer "In11.Cu")
		(net "FM_BMC_PWRBTN_OUT_N")
	)
	(segment
		(start 320.065146 -29.057346)
		(end 318.023748 -27.015948)
		(width 0.127)
		(layer "In11.Cu")
		(net "FM_BMC_PWRBTN_OUT_N")
	)
	(segment
		(start 271.50568 -37.353748)
		(end 271.07388 -36.921948)
		(width 0.127)
		(layer "In11.Cu")
		(net "FM_BMC_PWRBTN_OUT_N")
	)
	(segment
		(start 305.36388 -32.757618)
		(end 305.36388 -36.135818)
		(width 0.127)
		(layer "In11.Cu")
		(net "FM_BMC_PWRBTN_OUT_N")
	)
	(segment
		(start 318.023748 -27.015948)
		(end 311.10555 -27.015948)
		(width 0.127)
		(layer "In11.Cu")
		(net "FM_BMC_PWRBTN_OUT_N")
	)
	(segment
		(start 308.615334 -31.765748)
		(end 306.35575 -31.765748)
		(width 0.127)
		(layer "In11.Cu")
		(net "FM_BMC_PWRBTN_OUT_N")
	)
	(segment
		(start 311.10555 -27.015948)
		(end 310.261 -27.860498)
		(width 0.127)
		(layer "In11.Cu")
		(net "FM_BMC_PWRBTN_OUT_N")
	)
	(segment
		(start 272.00098 -41.877488)
		(end 269.19682 -44.681648)
		(width 0.127)
		(layer "In13.Cu")
		(net "FM_BMC_PWRBTN_OUT_N")
	)
	(segment
		(start 202.821032 -33.20034)
		(end 195.115434 -33.20034)
		(width 0.127)
		(layer "In13.Cu")
		(net "FM_BMC_PWRBTN_OUT_N")
	)
	(segment
		(start 185.907426 -35.677348)
		(end 184.688226 -36.896548)
		(width 0.127)
		(layer "In13.Cu")
		(net "FM_BMC_PWRBTN_OUT_N")
	)
	(segment
		(start 269.19682 -44.681648)
		(end 265.75512 -44.681648)
		(width 0.127)
		(layer "In13.Cu")
		(net "FM_BMC_PWRBTN_OUT_N")
	)
	(segment
		(start 168.48328 -29.049218)
		(end 168.48328 -19.897598)
		(width 0.127)
		(layer "In13.Cu")
		(net "FM_BMC_PWRBTN_OUT_N")
	)
	(segment
		(start 223.49968 -44.268136)
		(end 223.49968 -41.66743)
		(width 0.127)
		(layer "In13.Cu")
		(net "FM_BMC_PWRBTN_OUT_N")
	)
	(segment
		(start 150.04542 -18.301208)
		(end 147.30222 -18.301208)
		(width 0.127)
		(layer "In13.Cu")
		(net "FM_BMC_PWRBTN_OUT_N")
	)
	(segment
		(start 228.218492 -48.986948)
		(end 223.49968 -44.268136)
		(width 0.127)
		(layer "In13.Cu")
		(net "FM_BMC_PWRBTN_OUT_N")
	)
	(segment
		(start 151.84628 -16.500348)
		(end 150.04542 -18.301208)
		(width 0.127)
		(layer "In13.Cu")
		(net "FM_BMC_PWRBTN_OUT_N")
	)
	(segment
		(start 192.079626 -36.236148)
		(end 189.41288 -36.236148)
		(width 0.127)
		(layer "In13.Cu")
		(net "FM_BMC_PWRBTN_OUT_N")
	)
	(segment
		(start 168.48328 -19.897598)
		(end 168.78808 -19.592798)
		(width 0.127)
		(layer "In13.Cu")
		(net "FM_BMC_PWRBTN_OUT_N")
	)
	(segment
		(start 234.528868 -48.621188)
		(end 234.163108 -48.986948)
		(width 0.127)
		(layer "In13.Cu")
		(net "FM_BMC_PWRBTN_OUT_N")
	)
	(segment
		(start 204.255624 -31.765748)
		(end 202.821032 -33.20034)
		(width 0.127)
		(layer "In13.Cu")
		(net "FM_BMC_PWRBTN_OUT_N")
	)
	(segment
		(start 240.656618 -48.454818)
		(end 240.656618 -50.645822)
		(width 0.127)
		(layer "In13.Cu")
		(net "FM_BMC_PWRBTN_OUT_N")
	)
	(segment
		(start 235.260134 -48.621188)
		(end 234.528868 -48.621188)
		(width 0.127)
		(layer "In13.Cu")
		(net "FM_BMC_PWRBTN_OUT_N")
	)
	(segment
		(start 265.75512 -44.681648)
		(end 265.15187 -45.284898)
		(width 0.127)
		(layer "In13.Cu")
		(net "FM_BMC_PWRBTN_OUT_N")
	)
	(segment
		(start 184.688226 -36.896548)
		(end 176.33061 -36.896548)
		(width 0.127)
		(layer "In13.Cu")
		(net "FM_BMC_PWRBTN_OUT_N")
	)
	(segment
		(start 248.56313 -45.284898)
		(end 245.83771 -48.010318)
		(width 0.127)
		(layer "In13.Cu")
		(net "FM_BMC_PWRBTN_OUT_N")
	)
	(segment
		(start 234.163108 -48.986948)
		(end 228.218492 -48.986948)
		(width 0.127)
		(layer "In13.Cu")
		(net "FM_BMC_PWRBTN_OUT_N")
	)
	(segment
		(start 238.961168 -51.07178)
		(end 238.266478 -50.37709)
		(width 0.127)
		(layer "In13.Cu")
		(net "FM_BMC_PWRBTN_OUT_N")
	)
	(segment
		(start 238.266478 -50.37709)
		(end 237.016036 -50.37709)
		(width 0.127)
		(layer "In13.Cu")
		(net "FM_BMC_PWRBTN_OUT_N")
	)
	(segment
		(start 245.83771 -48.010318)
		(end 241.101118 -48.010318)
		(width 0.127)
		(layer "In13.Cu")
		(net "FM_BMC_PWRBTN_OUT_N")
	)
	(segment
		(start 176.33061 -36.896548)
		(end 168.48328 -29.049218)
		(width 0.127)
		(layer "In13.Cu")
		(net "FM_BMC_PWRBTN_OUT_N")
	)
	(segment
		(start 223.49968 -41.66743)
		(end 218.15552 -36.32327)
		(width 0.127)
		(layer "In13.Cu")
		(net "FM_BMC_PWRBTN_OUT_N")
	)
	(segment
		(start 168.78808 -19.592798)
		(end 168.78808 -17.109948)
		(width 0.127)
		(layer "In13.Cu")
		(net "FM_BMC_PWRBTN_OUT_N")
	)
	(segment
		(start 188.85408 -35.677348)
		(end 185.907426 -35.677348)
		(width 0.127)
		(layer "In13.Cu")
		(net "FM_BMC_PWRBTN_OUT_N")
	)
	(segment
		(start 265.15187 -45.284898)
		(end 248.56313 -45.284898)
		(width 0.127)
		(layer "In13.Cu")
		(net "FM_BMC_PWRBTN_OUT_N")
	)
	(segment
		(start 168.78808 -17.109948)
		(end 168.17848 -16.500348)
		(width 0.127)
		(layer "In13.Cu")
		(net "FM_BMC_PWRBTN_OUT_N")
	)
	(segment
		(start 217.33891 -31.765748)
		(end 204.255624 -31.765748)
		(width 0.127)
		(layer "In13.Cu")
		(net "FM_BMC_PWRBTN_OUT_N")
	)
	(segment
		(start 271.07388 -36.921948)
		(end 272.00098 -37.849048)
		(width 0.127)
		(layer "In13.Cu")
		(net "FM_BMC_PWRBTN_OUT_N")
	)
	(segment
		(start 240.23066 -51.07178)
		(end 238.961168 -51.07178)
		(width 0.127)
		(layer "In13.Cu")
		(net "FM_BMC_PWRBTN_OUT_N")
	)
	(segment
		(start 241.101118 -48.010318)
		(end 240.656618 -48.454818)
		(width 0.127)
		(layer "In13.Cu")
		(net "FM_BMC_PWRBTN_OUT_N")
	)
	(segment
		(start 168.17848 -16.500348)
		(end 151.84628 -16.500348)
		(width 0.127)
		(layer "In13.Cu")
		(net "FM_BMC_PWRBTN_OUT_N")
	)
	(segment
		(start 240.656618 -50.645822)
		(end 240.23066 -51.07178)
		(width 0.127)
		(layer "In13.Cu")
		(net "FM_BMC_PWRBTN_OUT_N")
	)
	(segment
		(start 189.41288 -36.236148)
		(end 188.85408 -35.677348)
		(width 0.127)
		(layer "In13.Cu")
		(net "FM_BMC_PWRBTN_OUT_N")
	)
	(segment
		(start 237.016036 -50.37709)
		(end 235.260134 -48.621188)
		(width 0.127)
		(layer "In13.Cu")
		(net "FM_BMC_PWRBTN_OUT_N")
	)
	(segment
		(start 272.00098 -37.849048)
		(end 272.00098 -41.877488)
		(width 0.127)
		(layer "In13.Cu")
		(net "FM_BMC_PWRBTN_OUT_N")
	)
	(segment
		(start 218.15552 -32.582358)
		(end 217.33891 -31.765748)
		(width 0.127)
		(layer "In13.Cu")
		(net "FM_BMC_PWRBTN_OUT_N")
	)
	(segment
		(start 195.115434 -33.20034)
		(end 192.079626 -36.236148)
		(width 0.127)
		(layer "In13.Cu")
		(net "FM_BMC_PWRBTN_OUT_N")
	)
	(segment
		(start 218.15552 -36.32327)
		(end 218.15552 -32.582358)
		(width 0.127)
		(layer "In13.Cu")
		(net "FM_BMC_PWRBTN_OUT_N")
	)
	(segment
		(start 319.668906 -27.051508)
		(end 319.668906 -27.752802)
		(width 0.12954)
		(layer "F.Cu")
		(net "FM_BMC_PWRBTN_N")
	)
	(segment
		(start 330.79436 -43.281346)
		(end 330.253848 -43.281346)
		(width 0.12954)
		(layer "F.Cu")
		(net "FM_BMC_PWRBTN_N")
	)
	(via
		(at 326.774302 -41.016682)
		(size 0.6604)
		(drill 0.3302)
		(layers "F.Cu" "B.Cu")
		(net "FM_BMC_PWRBTN_N")
	)
	(via
		(at 319.668906 -27.752802)
		(size 0.508)
		(drill 0.254)
		(layers "F.Cu" "B.Cu")
		(net "FM_BMC_PWRBTN_N")
	)
	(via
		(at 330.253848 -43.281346)
		(size 0.4572)
		(drill 0.2032)
		(layers "F.Cu" "B.Cu")
		(net "FM_BMC_PWRBTN_N")
	)
	(segment
		(start 326.017636 -39.031672)
		(end 325.791068 -39.031672)
		(width 0.12954)
		(layer "B.Cu")
		(net "FM_BMC_PWRBTN_N")
	)
	(segment
		(start 326.551798 -39.498778)
		(end 326.459342 -39.275512)
		(width 0.12954)
		(layer "B.Cu")
		(net "FM_BMC_PWRBTN_N")
	)
	(segment
		(start 320.437256 -34.262568)
		(end 319.58153 -33.406842)
		(width 0.12954)
		(layer "B.Cu")
		(net "FM_BMC_PWRBTN_N")
	)
	(segment
		(start 319.58153 -33.406842)
		(end 319.58153 -32.870648)
		(width 0.12954)
		(layer "B.Cu")
		(net "FM_BMC_PWRBTN_N")
	)
	(segment
		(start 330.253848 -43.281346)
		(end 329.794108 -42.671492)
		(width 0.0889)
		(layer "B.Cu")
		(net "FM_BMC_PWRBTN_N")
	)
	(segment
		(start 328.341736 -41.966896)
		(end 328.182224 -42.126408)
		(width 0.0889)
		(layer "B.Cu")
		(net "FM_BMC_PWRBTN_N")
	)
	(segment
		(start 319.58153 -32.838898)
		(end 319.58153 -32.870648)
		(width 0.12954)
		(layer "B.Cu")
		(net "FM_BMC_PWRBTN_N")
	)
	(segment
		(start 326.551798 -40.478964)
		(end 326.551798 -39.498778)
		(width 0.12954)
		(layer "B.Cu")
		(net "FM_BMC_PWRBTN_N")
	)
	(segment
		(start 326.355456 -39.171626)
		(end 326.017636 -39.031672)
		(width 0.12954)
		(layer "B.Cu")
		(net "FM_BMC_PWRBTN_N")
	)
	(segment
		(start 327.884028 -42.126408)
		(end 327.344532 -41.586912)
		(width 0.0889)
		(layer "B.Cu")
		(net "FM_BMC_PWRBTN_N")
	)
	(segment
		(start 324.829932 -38.070536)
		(end 324.829932 -37.728144)
		(width 0.12954)
		(layer "B.Cu")
		(net "FM_BMC_PWRBTN_N")
	)
	(segment
		(start 321.158362 -34.056574)
		(end 320.952368 -34.262568)
		(width 0.12954)
		(layer "B.Cu")
		(net "FM_BMC_PWRBTN_N")
	)
	(segment
		(start 328.182224 -42.126408)
		(end 327.884028 -42.126408)
		(width 0.0889)
		(layer "B.Cu")
		(net "FM_BMC_PWRBTN_N")
	)
	(segment
		(start 320.952368 -34.262568)
		(end 320.437256 -34.262568)
		(width 0.12954)
		(layer "B.Cu")
		(net "FM_BMC_PWRBTN_N")
	)
	(segment
		(start 320.17208 -29.987748)
		(end 320.17208 -32.248348)
		(width 0.12954)
		(layer "B.Cu")
		(net "FM_BMC_PWRBTN_N")
	)
	(segment
		(start 329.765152 -42.623994)
		(end 329.765152 -42.62374)
		(width 0.0889)
		(layer "B.Cu")
		(net "FM_BMC_PWRBTN_N")
	)
	(segment
		(start 324.829932 -37.728144)
		(end 321.158362 -34.056574)
		(width 0.12954)
		(layer "B.Cu")
		(net "FM_BMC_PWRBTN_N")
	)
	(segment
		(start 320.85788 -29.301948)
		(end 320.17208 -29.987748)
		(width 0.12954)
		(layer "B.Cu")
		(net "FM_BMC_PWRBTN_N")
	)
	(segment
		(start 319.668906 -27.752802)
		(end 320.85788 -28.941776)
		(width 0.12954)
		(layer "B.Cu")
		(net "FM_BMC_PWRBTN_N")
	)
	(segment
		(start 328.625708 -41.966896)
		(end 328.341736 -41.966896)
		(width 0.0889)
		(layer "B.Cu")
		(net "FM_BMC_PWRBTN_N")
	)
	(segment
		(start 329.7809 -42.649648)
		(end 329.765152 -42.623994)
		(width 0.0889)
		(layer "B.Cu")
		(net "FM_BMC_PWRBTN_N")
	)
	(segment
		(start 320.85788 -28.941776)
		(end 320.85788 -29.301948)
		(width 0.12954)
		(layer "B.Cu")
		(net "FM_BMC_PWRBTN_N")
	)
	(segment
		(start 326.459342 -39.275512)
		(end 326.355456 -39.171626)
		(width 0.12954)
		(layer "B.Cu")
		(net "FM_BMC_PWRBTN_N")
	)
	(segment
		(start 326.774302 -41.016682)
		(end 326.551798 -40.478964)
		(width 0.12954)
		(layer "B.Cu")
		(net "FM_BMC_PWRBTN_N")
	)
	(segment
		(start 329.794108 -42.671492)
		(end 329.7809 -42.649648)
		(width 0.0889)
		(layer "B.Cu")
		(net "FM_BMC_PWRBTN_N")
	)
	(segment
		(start 328.950066 -42.154348)
		(end 328.944986 -42.145458)
		(width 0.0889)
		(layer "B.Cu")
		(net "FM_BMC_PWRBTN_N")
	)
	(segment
		(start 329.440794 -42.436796)
		(end 329.422252 -42.43705)
		(width 0.0889)
		(layer "B.Cu")
		(net "FM_BMC_PWRBTN_N")
	)
	(segment
		(start 320.17208 -32.248348)
		(end 319.58153 -32.838898)
		(width 0.12954)
		(layer "B.Cu")
		(net "FM_BMC_PWRBTN_N")
	)
	(segment
		(start 325.791068 -39.031672)
		(end 324.829932 -38.070536)
		(width 0.12954)
		(layer "B.Cu")
		(net "FM_BMC_PWRBTN_N")
	)
	(segment
		(start 327.344532 -41.586912)
		(end 326.774302 -41.016682)
		(width 0.12954)
		(layer "B.Cu")
		(net "FM_BMC_PWRBTN_N")
	)
	(arc
		(start 329.765152 -42.62374)
		(mid 329.62805 -42.486721)
		(end 329.440794 -42.436796)
		(width 0.0889)
		(layer "B.Cu")
		(net "FM_BMC_PWRBTN_N")
	)
	(arc
		(start 329.422252 -42.43705)
		(mid 329.149491 -42.356974)
		(end 328.950066 -42.154348)
		(width 0.0889)
		(layer "B.Cu")
		(net "FM_BMC_PWRBTN_N")
	)
	(arc
		(start 328.944986 -42.145458)
		(mid 328.808626 -42.014544)
		(end 328.625708 -41.966896)
		(width 0.0889)
		(layer "B.Cu")
		(net "FM_BMC_PWRBTN_N")
	)
	(segment
		(start 101.270816 -56.38292)
		(end 101.270816 -54.956964)
		(width 0.12954)
		(layer "F.Cu")
		(net "FM_BMC_EN_DET")
	)
	(segment
		(start 96.97593 -55.209948)
		(end 97.55886 -54.627018)
		(width 0.12954)
		(layer "F.Cu")
		(net "FM_BMC_EN_DET")
	)
	(segment
		(start 104.696768 -53.977032)
		(end 105.76941 -53.977032)
		(width 0.12954)
		(layer "F.Cu")
		(net "FM_BMC_EN_DET")
	)
	(segment
		(start 98.79711 -54.627018)
		(end 99.92741 -54.627018)
		(width 0.12954)
		(layer "F.Cu")
		(net "FM_BMC_EN_DET")
	)
	(segment
		(start 104.392984 -54.280816)
		(end 104.696768 -53.977032)
		(width 0.12954)
		(layer "F.Cu")
		(net "FM_BMC_EN_DET")
	)
	(segment
		(start 100.94087 -54.627018)
		(end 99.92741 -54.627018)
		(width 0.12954)
		(layer "F.Cu")
		(net "FM_BMC_EN_DET")
	)
	(segment
		(start 104.392984 -55.583836)
		(end 104.392984 -54.280816)
		(width 0.12954)
		(layer "F.Cu")
		(net "FM_BMC_EN_DET")
	)
	(segment
		(start 101.270816 -54.956964)
		(end 100.94087 -54.627018)
		(width 0.12954)
		(layer "F.Cu")
		(net "FM_BMC_EN_DET")
	)
	(segment
		(start 96.97593 -54.066948)
		(end 96.46793 -54.574948)
		(width 0.12954)
		(layer "F.Cu")
		(net "FM_BMC_EN_DET")
	)
	(segment
		(start 94.92488 -54.574948)
		(end 92.874846 -54.574948)
		(width 0.12954)
		(layer "F.Cu")
		(net "FM_BMC_EN_DET")
	)
	(segment
		(start 92.874846 -54.574948)
		(end 92.173806 -55.275988)
		(width 0.12954)
		(layer "F.Cu")
		(net "FM_BMC_EN_DET")
	)
	(segment
		(start 96.46793 -54.574948)
		(end 94.92488 -54.574948)
		(width 0.12954)
		(layer "F.Cu")
		(net "FM_BMC_EN_DET")
	)
	(segment
		(start 105.76941 -55.92699)
		(end 104.736138 -55.92699)
		(width 0.12954)
		(layer "F.Cu")
		(net "FM_BMC_EN_DET")
	)
	(segment
		(start 104.736138 -55.92699)
		(end 104.392984 -55.583836)
		(width 0.12954)
		(layer "F.Cu")
		(net "FM_BMC_EN_DET")
	)
	(segment
		(start 99.92741 -56.576976)
		(end 101.07676 -56.576976)
		(width 0.12954)
		(layer "F.Cu")
		(net "FM_BMC_EN_DET")
	)
	(segment
		(start 96.97593 -55.209948)
		(end 96.97593 -54.066948)
		(width 0.12954)
		(layer "F.Cu")
		(net "FM_BMC_EN_DET")
	)
	(segment
		(start 97.55886 -54.627018)
		(end 98.79711 -54.627018)
		(width 0.12954)
		(layer "F.Cu")
		(net "FM_BMC_EN_DET")
	)
	(segment
		(start 101.07676 -56.576976)
		(end 101.270816 -56.38292)
		(width 0.12954)
		(layer "F.Cu")
		(net "FM_BMC_EN_DET")
	)
	(via
		(at 94.92488 -54.574948)
		(size 0.762)
		(drill 0.381)
		(layers "F.Cu" "B.Cu")
		(net "FM_BMC_EN_DET")
	)
	(via
		(at 104.392984 -55.583836)
		(size 0.508)
		(drill 0.254)
		(layers "F.Cu" "B.Cu")
		(net "FM_BMC_EN_DET")
	)
	(via
		(at 98.79711 -54.627018)
		(size 0.508)
		(drill 0.254)
		(layers "F.Cu" "B.Cu")
		(net "FM_BMC_EN_DET")
	)
	(segment
		(start 104.392984 -55.583836)
		(end 99.753928 -55.583836)
		(width 0.12954)
		(layer "B.Cu")
		(net "FM_BMC_EN_DET")
	)
	(segment
		(start 99.753928 -55.583836)
		(end 98.79711 -54.627018)
		(width 0.12954)
		(layer "B.Cu")
		(net "FM_BMC_EN_DET")
	)
	(segment
		(start 385.316222 -58.703464)
		(end 384.68808 -58.703464)
		(width 0.12954)
		(layer "F.Cu")
		(net "FM_BMC_DBP_PRESENT_R_N")
	)
	(segment
		(start 182.955692 -110.575344)
		(end 183.355742 -110.175294)
		(width 0.12954)
		(layer "F.Cu")
		(net "FM_BMC_DBP_PRESENT_R_N")
	)
	(via
		(at 183.355742 -110.175294)
		(size 0.4572)
		(drill 0.254)
		(layers "F.Cu" "B.Cu")
		(net "FM_BMC_DBP_PRESENT_R_N")
	)
	(via
		(at 384.68808 -58.703464)
		(size 0.508)
		(drill 0.254)
		(layers "F.Cu" "B.Cu")
		(net "FM_BMC_DBP_PRESENT_R_N")
	)
	(segment
		(start 268.65834 -114.391948)
		(end 280.292048 -114.391948)
		(width 0.127)
		(layer "In15.Cu")
		(net "FM_BMC_DBP_PRESENT_R_N")
	)
	(segment
		(start 219.84208 -102.870508)
		(end 231.677972 -102.870508)
		(width 0.127)
		(layer "In15.Cu")
		(net "FM_BMC_DBP_PRESENT_R_N")
	)
	(segment
		(start 379.19914 -89.47531)
		(end 371.949218 -82.225388)
		(width 0.127)
		(layer "In15.Cu")
		(net "FM_BMC_DBP_PRESENT_R_N")
	)
	(segment
		(start 183.754268 -109.776768)
		(end 186.00674 -109.776768)
		(width 0.127)
		(layer "In15.Cu")
		(net "FM_BMC_DBP_PRESENT_R_N")
	)
	(segment
		(start 188.429138 -109.479588)
		(end 193.676778 -104.231948)
		(width 0.127)
		(layer "In15.Cu")
		(net "FM_BMC_DBP_PRESENT_R_N")
	)
	(segment
		(start 371.949218 -82.225388)
		(end 371.949218 -71.837296)
		(width 0.127)
		(layer "In15.Cu")
		(net "FM_BMC_DBP_PRESENT_R_N")
	)
	(segment
		(start 376.701812 -111.468408)
		(end 382.77546 -105.39476)
		(width 0.127)
		(layer "In15.Cu")
		(net "FM_BMC_DBP_PRESENT_R_N")
	)
	(segment
		(start 382.77546 -105.39476)
		(end 382.77546 -100.909628)
		(width 0.127)
		(layer "In15.Cu")
		(net "FM_BMC_DBP_PRESENT_R_N")
	)
	(segment
		(start 280.292048 -114.391948)
		(end 283.215588 -111.468408)
		(width 0.127)
		(layer "In15.Cu")
		(net "FM_BMC_DBP_PRESENT_R_N")
	)
	(segment
		(start 183.355742 -110.175294)
		(end 183.754268 -109.776768)
		(width 0.127)
		(layer "In15.Cu")
		(net "FM_BMC_DBP_PRESENT_R_N")
	)
	(segment
		(start 231.677972 -102.870508)
		(end 234.944412 -106.136948)
		(width 0.127)
		(layer "In15.Cu")
		(net "FM_BMC_DBP_PRESENT_R_N")
	)
	(segment
		(start 379.19914 -97.333308)
		(end 379.19914 -89.47531)
		(width 0.127)
		(layer "In15.Cu")
		(net "FM_BMC_DBP_PRESENT_R_N")
	)
	(segment
		(start 385.85648 -64.432688)
		(end 385.85648 -59.871864)
		(width 0.127)
		(layer "In15.Cu")
		(net "FM_BMC_DBP_PRESENT_R_N")
	)
	(segment
		(start 186.00674 -109.776768)
		(end 186.30392 -109.479588)
		(width 0.127)
		(layer "In15.Cu")
		(net "FM_BMC_DBP_PRESENT_R_N")
	)
	(segment
		(start 376.289062 -67.497452)
		(end 382.791716 -67.497452)
		(width 0.127)
		(layer "In15.Cu")
		(net "FM_BMC_DBP_PRESENT_R_N")
	)
	(segment
		(start 283.215588 -111.468408)
		(end 376.701812 -111.468408)
		(width 0.127)
		(layer "In15.Cu")
		(net "FM_BMC_DBP_PRESENT_R_N")
	)
	(segment
		(start 251.192792 -116.081048)
		(end 266.96924 -116.081048)
		(width 0.127)
		(layer "In15.Cu")
		(net "FM_BMC_DBP_PRESENT_R_N")
	)
	(segment
		(start 193.676778 -104.231948)
		(end 206.89062 -104.231948)
		(width 0.127)
		(layer "In15.Cu")
		(net "FM_BMC_DBP_PRESENT_R_N")
	)
	(segment
		(start 186.30392 -109.479588)
		(end 188.429138 -109.479588)
		(width 0.127)
		(layer "In15.Cu")
		(net "FM_BMC_DBP_PRESENT_R_N")
	)
	(segment
		(start 382.77546 -100.909628)
		(end 379.19914 -97.333308)
		(width 0.127)
		(layer "In15.Cu")
		(net "FM_BMC_DBP_PRESENT_R_N")
	)
	(segment
		(start 385.85648 -59.871864)
		(end 384.68808 -58.703464)
		(width 0.127)
		(layer "In15.Cu")
		(net "FM_BMC_DBP_PRESENT_R_N")
	)
	(segment
		(start 219.400628 -102.429056)
		(end 219.84208 -102.870508)
		(width 0.127)
		(layer "In15.Cu")
		(net "FM_BMC_DBP_PRESENT_R_N")
	)
	(segment
		(start 241.248692 -106.136948)
		(end 251.192792 -116.081048)
		(width 0.127)
		(layer "In15.Cu")
		(net "FM_BMC_DBP_PRESENT_R_N")
	)
	(segment
		(start 208.693512 -102.429056)
		(end 219.400628 -102.429056)
		(width 0.127)
		(layer "In15.Cu")
		(net "FM_BMC_DBP_PRESENT_R_N")
	)
	(segment
		(start 234.944412 -106.136948)
		(end 241.248692 -106.136948)
		(width 0.127)
		(layer "In15.Cu")
		(net "FM_BMC_DBP_PRESENT_R_N")
	)
	(segment
		(start 206.89062 -104.231948)
		(end 208.693512 -102.429056)
		(width 0.127)
		(layer "In15.Cu")
		(net "FM_BMC_DBP_PRESENT_R_N")
	)
	(segment
		(start 382.791716 -67.497452)
		(end 385.85648 -64.432688)
		(width 0.127)
		(layer "In15.Cu")
		(net "FM_BMC_DBP_PRESENT_R_N")
	)
	(segment
		(start 371.949218 -71.837296)
		(end 376.289062 -67.497452)
		(width 0.127)
		(layer "In15.Cu")
		(net "FM_BMC_DBP_PRESENT_R_N")
	)
	(segment
		(start 266.96924 -116.081048)
		(end 268.65834 -114.391948)
		(width 0.127)
		(layer "In15.Cu")
		(net "FM_BMC_DBP_PRESENT_R_N")
	)
	(segment
		(start 195.95846 -90.155268)
		(end 196.07784 -90.274648)
		(width 0.12954)
		(layer "F.Cu")
		(net "FM_BMC_CPU_FBRK_OUT_R_N")
	)
	(segment
		(start 183.755538 -118.575328)
		(end 184.155588 -118.975378)
		(width 0.12954)
		(layer "F.Cu")
		(net "FM_BMC_CPU_FBRK_OUT_R_N")
	)
	(segment
		(start 196.07784 -90.274648)
		(end 196.07784 -92.432378)
		(width 0.12954)
		(layer "F.Cu")
		(net "FM_BMC_CPU_FBRK_OUT_R_N")
	)
	(via
		(at 184.155588 -118.975378)
		(size 0.4572)
		(drill 0.254)
		(layers "F.Cu" "B.Cu")
		(net "FM_BMC_CPU_FBRK_OUT_R_N")
	)
	(via
		(at 195.95846 -90.155268)
		(size 0.762)
		(drill 0.254)
		(layers "F.Cu" "B.Cu")
		(net "FM_BMC_CPU_FBRK_OUT_R_N")
	)
	(segment
		(start 189.272672 -99.233228)
		(end 187.563252 -100.942648)
		(width 0.127)
		(layer "In13.Cu")
		(net "FM_BMC_CPU_FBRK_OUT_R_N")
	)
	(segment
		(start 184.5564 -118.574566)
		(end 184.155588 -118.975378)
		(width 0.127)
		(layer "In13.Cu")
		(net "FM_BMC_CPU_FBRK_OUT_R_N")
	)
	(segment
		(start 195.95846 -90.155268)
		(end 195.95846 -90.670888)
		(width 0.127)
		(layer "In13.Cu")
		(net "FM_BMC_CPU_FBRK_OUT_R_N")
	)
	(segment
		(start 185.674 -101.458268)
		(end 185.674 -103.693468)
		(width 0.127)
		(layer "In13.Cu")
		(net "FM_BMC_CPU_FBRK_OUT_R_N")
	)
	(segment
		(start 195.95846 -90.670888)
		(end 191.5922 -95.037148)
		(width 0.127)
		(layer "In13.Cu")
		(net "FM_BMC_CPU_FBRK_OUT_R_N")
	)
	(segment
		(start 191.5922 -98.064574)
		(end 190.423546 -99.233228)
		(width 0.127)
		(layer "In13.Cu")
		(net "FM_BMC_CPU_FBRK_OUT_R_N")
	)
	(segment
		(start 186.18962 -100.942648)
		(end 185.674 -101.458268)
		(width 0.127)
		(layer "In13.Cu")
		(net "FM_BMC_CPU_FBRK_OUT_R_N")
	)
	(segment
		(start 185.674 -103.693468)
		(end 184.5564 -104.811068)
		(width 0.127)
		(layer "In13.Cu")
		(net "FM_BMC_CPU_FBRK_OUT_R_N")
	)
	(segment
		(start 191.5922 -95.037148)
		(end 191.5922 -98.064574)
		(width 0.127)
		(layer "In13.Cu")
		(net "FM_BMC_CPU_FBRK_OUT_R_N")
	)
	(segment
		(start 187.563252 -100.942648)
		(end 186.18962 -100.942648)
		(width 0.127)
		(layer "In13.Cu")
		(net "FM_BMC_CPU_FBRK_OUT_R_N")
	)
	(segment
		(start 190.423546 -99.233228)
		(end 189.272672 -99.233228)
		(width 0.127)
		(layer "In13.Cu")
		(net "FM_BMC_CPU_FBRK_OUT_R_N")
	)
	(segment
		(start 184.5564 -104.811068)
		(end 184.5564 -118.574566)
		(width 0.127)
		(layer "In13.Cu")
		(net "FM_BMC_CPU_FBRK_OUT_R_N")
	)
	(segment
		(start 368.1984 -97.665794)
		(end 365.915956 -95.38335)
		(width 0.12954)
		(layer "F.Cu")
		(net "FM_BMC_CPU_FBRK_OUT_N")
	)
	(segment
		(start 365.915956 -95.38335)
		(end 302.28794 -95.38335)
		(width 0.12954)
		(layer "F.Cu")
		(net "FM_BMC_CPU_FBRK_OUT_N")
	)
	(segment
		(start 196.07784 -93.232478)
		(end 196.07784 -95.291148)
		(width 0.12954)
		(layer "F.Cu")
		(net "FM_BMC_CPU_FBRK_OUT_N")
	)
	(segment
		(start 368.1984 -100.771198)
		(end 368.1984 -97.665794)
		(width 0.12954)
		(layer "F.Cu")
		(net "FM_BMC_CPU_FBRK_OUT_N")
	)
	(segment
		(start 371.022372 -101.19868)
		(end 371.022372 -102.106984)
		(width 0.12954)
		(layer "F.Cu")
		(net "FM_BMC_CPU_FBRK_OUT_N")
	)
	(segment
		(start 298.669964 -91.765374)
		(end 294.577262 -91.765374)
		(width 0.12954)
		(layer "F.Cu")
		(net "FM_BMC_CPU_FBRK_OUT_N")
	)
	(segment
		(start 370.59489 -100.771198)
		(end 371.022372 -101.19868)
		(width 0.12954)
		(layer "F.Cu")
		(net "FM_BMC_CPU_FBRK_OUT_N")
	)
	(segment
		(start 302.28794 -95.38335)
		(end 298.669964 -91.765374)
		(width 0.12954)
		(layer "F.Cu")
		(net "FM_BMC_CPU_FBRK_OUT_N")
	)
	(segment
		(start 368.1984 -100.771198)
		(end 370.59489 -100.771198)
		(width 0.12954)
		(layer "F.Cu")
		(net "FM_BMC_CPU_FBRK_OUT_N")
	)
	(via
		(at 294.577262 -91.765374)
		(size 0.508)
		(drill 0.254)
		(layers "F.Cu" "B.Cu")
		(net "FM_BMC_CPU_FBRK_OUT_N")
	)
	(via
		(at 196.07784 -95.291148)
		(size 0.508)
		(drill 0.254)
		(layers "F.Cu" "B.Cu")
		(net "FM_BMC_CPU_FBRK_OUT_N")
	)
	(segment
		(start 247.0658 -91.506548)
		(end 249.6058 -94.046548)
		(width 0.127)
		(layer "In15.Cu")
		(net "FM_BMC_CPU_FBRK_OUT_N")
	)
	(segment
		(start 196.544692 -95.758)
		(end 202.3364 -95.758)
		(width 0.127)
		(layer "In15.Cu")
		(net "FM_BMC_CPU_FBRK_OUT_N")
	)
	(segment
		(start 204.073252 -94.021148)
		(end 211.38261 -94.021148)
		(width 0.127)
		(layer "In15.Cu")
		(net "FM_BMC_CPU_FBRK_OUT_N")
	)
	(segment
		(start 256.5146 -91.125548)
		(end 293.937436 -91.125548)
		(width 0.127)
		(layer "In15.Cu")
		(net "FM_BMC_CPU_FBRK_OUT_N")
	)
	(segment
		(start 202.3364 -95.758)
		(end 204.073252 -94.021148)
		(width 0.127)
		(layer "In15.Cu")
		(net "FM_BMC_CPU_FBRK_OUT_N")
	)
	(segment
		(start 222.556832 -92.852748)
		(end 242.8748 -92.852748)
		(width 0.127)
		(layer "In15.Cu")
		(net "FM_BMC_CPU_FBRK_OUT_N")
	)
	(segment
		(start 250.486418 -94.368366)
		(end 252.719586 -94.368366)
		(width 0.127)
		(layer "In15.Cu")
		(net "FM_BMC_CPU_FBRK_OUT_N")
	)
	(segment
		(start 244.221 -91.506548)
		(end 247.0658 -91.506548)
		(width 0.127)
		(layer "In15.Cu")
		(net "FM_BMC_CPU_FBRK_OUT_N")
	)
	(segment
		(start 242.8748 -92.852748)
		(end 244.221 -91.506548)
		(width 0.127)
		(layer "In15.Cu")
		(net "FM_BMC_CPU_FBRK_OUT_N")
	)
	(segment
		(start 252.719586 -94.368366)
		(end 253.295658 -94.944438)
		(width 0.127)
		(layer "In15.Cu")
		(net "FM_BMC_CPU_FBRK_OUT_N")
	)
	(segment
		(start 211.38261 -94.021148)
		(end 213.184486 -92.219272)
		(width 0.127)
		(layer "In15.Cu")
		(net "FM_BMC_CPU_FBRK_OUT_N")
	)
	(segment
		(start 254.8636 -92.776548)
		(end 256.5146 -91.125548)
		(width 0.127)
		(layer "In15.Cu")
		(net "FM_BMC_CPU_FBRK_OUT_N")
	)
	(segment
		(start 293.937436 -91.125548)
		(end 294.577262 -91.765374)
		(width 0.127)
		(layer "In15.Cu")
		(net "FM_BMC_CPU_FBRK_OUT_N")
	)
	(segment
		(start 254.29591 -94.944438)
		(end 254.8636 -94.376748)
		(width 0.127)
		(layer "In15.Cu")
		(net "FM_BMC_CPU_FBRK_OUT_N")
	)
	(segment
		(start 254.8636 -94.376748)
		(end 254.8636 -92.776548)
		(width 0.127)
		(layer "In15.Cu")
		(net "FM_BMC_CPU_FBRK_OUT_N")
	)
	(segment
		(start 249.6058 -94.046548)
		(end 250.1646 -94.046548)
		(width 0.127)
		(layer "In15.Cu")
		(net "FM_BMC_CPU_FBRK_OUT_N")
	)
	(segment
		(start 213.184486 -92.219272)
		(end 221.923356 -92.219272)
		(width 0.127)
		(layer "In15.Cu")
		(net "FM_BMC_CPU_FBRK_OUT_N")
	)
	(segment
		(start 196.07784 -95.291148)
		(end 196.544692 -95.758)
		(width 0.127)
		(layer "In15.Cu")
		(net "FM_BMC_CPU_FBRK_OUT_N")
	)
	(segment
		(start 253.295658 -94.944438)
		(end 254.29591 -94.944438)
		(width 0.127)
		(layer "In15.Cu")
		(net "FM_BMC_CPU_FBRK_OUT_N")
	)
	(segment
		(start 250.1646 -94.046548)
		(end 250.486418 -94.368366)
		(width 0.127)
		(layer "In15.Cu")
		(net "FM_BMC_CPU_FBRK_OUT_N")
	)
	(segment
		(start 221.923356 -92.219272)
		(end 222.556832 -92.852748)
		(width 0.127)
		(layer "In15.Cu")
		(net "FM_BMC_CPU_FBRK_OUT_N")
	)
	(segment
		(start 311.10428 -42.103548)
		(end 313.340496 -42.103548)
		(width 0.12954)
		(layer "F.Cu")
		(net "FM_BIOS_POST_CMPLT_N")
	)
	(segment
		(start 30.988 -52.669948)
		(end 30.988 -44.308268)
		(width 0.12954)
		(layer "F.Cu")
		(net "FM_BIOS_POST_CMPLT_N")
	)
	(segment
		(start 309.122572 -41.900348)
		(end 309.630572 -42.408348)
		(width 0.12954)
		(layer "F.Cu")
		(net "FM_BIOS_POST_CMPLT_N")
	)
	(segment
		(start 322.878704 -45.308266)
		(end 323.069204 -45.117766)
		(width 0.0889)
		(layer "F.Cu")
		(net "FM_BIOS_POST_CMPLT_N")
	)
	(segment
		(start 309.630572 -42.408348)
		(end 310.79948 -42.408348)
		(width 0.12954)
		(layer "F.Cu")
		(net "FM_BIOS_POST_CMPLT_N")
	)
	(segment
		(start 323.069204 -45.117766)
		(end 326.044306 -45.117766)
		(width 0.0889)
		(layer "F.Cu")
		(net "FM_BIOS_POST_CMPLT_N")
	)
	(segment
		(start 315.69787 -43.044364)
		(end 317.891414 -43.044364)
		(width 0.12954)
		(layer "F.Cu")
		(net "FM_BIOS_POST_CMPLT_N")
	)
	(segment
		(start 317.891414 -43.044364)
		(end 319.143634 -44.296584)
		(width 0.12954)
		(layer "F.Cu")
		(net "FM_BIOS_POST_CMPLT_N")
	)
	(segment
		(start 313.340496 -42.103548)
		(end 313.718956 -41.725088)
		(width 0.12954)
		(layer "F.Cu")
		(net "FM_BIOS_POST_CMPLT_N")
	)
	(segment
		(start 327.132696 -44.948602)
		(end 327.41489 -44.948602)
		(width 0.0889)
		(layer "F.Cu")
		(net "FM_BIOS_POST_CMPLT_N")
	)
	(segment
		(start 308.379114 -41.900348)
		(end 309.122572 -41.900348)
		(width 0.12954)
		(layer "F.Cu")
		(net "FM_BIOS_POST_CMPLT_N")
	)
	(segment
		(start 319.143634 -44.296584)
		(end 319.216786 -44.296584)
		(width 0.12954)
		(layer "F.Cu")
		(net "FM_BIOS_POST_CMPLT_N")
	)
	(segment
		(start 29.672534 -42.992802)
		(end 25.33142 -42.992802)
		(width 0.12954)
		(layer "F.Cu")
		(net "FM_BIOS_POST_CMPLT_N")
	)
	(segment
		(start 310.79948 -42.408348)
		(end 311.10428 -42.103548)
		(width 0.12954)
		(layer "F.Cu")
		(net "FM_BIOS_POST_CMPLT_N")
	)
	(segment
		(start 326.044306 -45.117766)
		(end 326.408796 -45.225208)
		(width 0.0889)
		(layer "F.Cu")
		(net "FM_BIOS_POST_CMPLT_N")
	)
	(segment
		(start 314.874656 -42.22115)
		(end 315.69787 -43.044364)
		(width 0.12954)
		(layer "F.Cu")
		(net "FM_BIOS_POST_CMPLT_N")
	)
	(segment
		(start 30.988 -44.308268)
		(end 29.672534 -42.992802)
		(width 0.12954)
		(layer "F.Cu")
		(net "FM_BIOS_POST_CMPLT_N")
	)
	(segment
		(start 313.718956 -41.725088)
		(end 314.874656 -41.725088)
		(width 0.12954)
		(layer "F.Cu")
		(net "FM_BIOS_POST_CMPLT_N")
	)
	(segment
		(start 320.228468 -45.308266)
		(end 322.575174 -45.308266)
		(width 0.12954)
		(layer "F.Cu")
		(net "FM_BIOS_POST_CMPLT_N")
	)
	(segment
		(start 314.874656 -41.725088)
		(end 314.874656 -42.22115)
		(width 0.12954)
		(layer "F.Cu")
		(net "FM_BIOS_POST_CMPLT_N")
	)
	(segment
		(start 326.718422 -45.225208)
		(end 327.132696 -44.948602)
		(width 0.0889)
		(layer "F.Cu")
		(net "FM_BIOS_POST_CMPLT_N")
	)
	(segment
		(start 307.763672 -41.900348)
		(end 308.379114 -41.900348)
		(width 0.12954)
		(layer "F.Cu")
		(net "FM_BIOS_POST_CMPLT_N")
	)
	(segment
		(start 322.575174 -45.308266)
		(end 322.878704 -45.308266)
		(width 0.0889)
		(layer "F.Cu")
		(net "FM_BIOS_POST_CMPLT_N")
	)
	(segment
		(start 326.408796 -45.225208)
		(end 326.718422 -45.225208)
		(width 0.0889)
		(layer "F.Cu")
		(net "FM_BIOS_POST_CMPLT_N")
	)
	(segment
		(start 319.216786 -44.296584)
		(end 320.228468 -45.308266)
		(width 0.12954)
		(layer "F.Cu")
		(net "FM_BIOS_POST_CMPLT_N")
	)
	(via
		(at 314.874656 -41.725088)
		(size 0.762)
		(drill 0.381)
		(layers "F.Cu" "B.Cu")
		(net "FM_BIOS_POST_CMPLT_N")
	)
	(via
		(at 290.057078 -57.728358)
		(size 0.508)
		(drill 0.254)
		(layers "F.Cu" "B.Cu")
		(net "FM_BIOS_POST_CMPLT_N")
	)
	(via
		(at 30.988 -52.669948)
		(size 0.508)
		(drill 0.254)
		(layers "F.Cu" "B.Cu")
		(net "FM_BIOS_POST_CMPLT_N")
	)
	(via
		(at 308.379114 -41.900348)
		(size 0.508)
		(drill 0.254)
		(layers "F.Cu" "B.Cu")
		(net "FM_BIOS_POST_CMPLT_N")
	)
	(segment
		(start 193.675 -81.125314)
		(end 176.443894 -81.125314)
		(width 0.127)
		(layer "In6.Cu")
		(net "FM_BIOS_POST_CMPLT_N")
	)
	(segment
		(start 286.163766 -72.885808)
		(end 276.360636 -82.688938)
		(width 0.127)
		(layer "In6.Cu")
		(net "FM_BIOS_POST_CMPLT_N")
	)
	(segment
		(start 239.76584 -87.83574)
		(end 212.731604 -87.83574)
		(width 0.127)
		(layer "In6.Cu")
		(net "FM_BIOS_POST_CMPLT_N")
	)
	(segment
		(start 69.67347 -66.614548)
		(end 58.406538 -55.347616)
		(width 0.127)
		(layer "In6.Cu")
		(net "FM_BIOS_POST_CMPLT_N")
	)
	(segment
		(start 244.912642 -82.688938)
		(end 239.76584 -87.83574)
		(width 0.127)
		(layer "In6.Cu")
		(net "FM_BIOS_POST_CMPLT_N")
	)
	(segment
		(start 148.011642 -64.818768)
		(end 139.637008 -64.818768)
		(width 0.127)
		(layer "In6.Cu")
		(net "FM_BIOS_POST_CMPLT_N")
	)
	(segment
		(start 206.543148 -81.647284)
		(end 198.8566 -81.647284)
		(width 0.127)
		(layer "In6.Cu")
		(net "FM_BIOS_POST_CMPLT_N")
	)
	(segment
		(start 198.174864 -80.965548)
		(end 193.834766 -80.965548)
		(width 0.127)
		(layer "In6.Cu")
		(net "FM_BIOS_POST_CMPLT_N")
	)
	(segment
		(start 30.988 -54.435248)
		(end 30.988 -52.669948)
		(width 0.127)
		(layer "In6.Cu")
		(net "FM_BIOS_POST_CMPLT_N")
	)
	(segment
		(start 290.057078 -59.114182)
		(end 286.163766 -63.007494)
		(width 0.127)
		(layer "In6.Cu")
		(net "FM_BIOS_POST_CMPLT_N")
	)
	(segment
		(start 212.731604 -87.83574)
		(end 206.543148 -81.647284)
		(width 0.127)
		(layer "In6.Cu")
		(net "FM_BIOS_POST_CMPLT_N")
	)
	(segment
		(start 176.443894 -81.125314)
		(end 163.44392 -68.12534)
		(width 0.127)
		(layer "In6.Cu")
		(net "FM_BIOS_POST_CMPLT_N")
	)
	(segment
		(start 149.629622 -66.436748)
		(end 148.011642 -64.818768)
		(width 0.127)
		(layer "In6.Cu")
		(net "FM_BIOS_POST_CMPLT_N")
	)
	(segment
		(start 133.4516 -66.614548)
		(end 69.67347 -66.614548)
		(width 0.127)
		(layer "In6.Cu")
		(net "FM_BIOS_POST_CMPLT_N")
	)
	(segment
		(start 151.950928 -66.436748)
		(end 149.629622 -66.436748)
		(width 0.127)
		(layer "In6.Cu")
		(net "FM_BIOS_POST_CMPLT_N")
	)
	(segment
		(start 58.406538 -55.347616)
		(end 31.900368 -55.347616)
		(width 0.127)
		(layer "In6.Cu")
		(net "FM_BIOS_POST_CMPLT_N")
	)
	(segment
		(start 153.63952 -68.12534)
		(end 151.950928 -66.436748)
		(width 0.127)
		(layer "In6.Cu")
		(net "FM_BIOS_POST_CMPLT_N")
	)
	(segment
		(start 134.850632 -65.215516)
		(end 133.4516 -66.614548)
		(width 0.127)
		(layer "In6.Cu")
		(net "FM_BIOS_POST_CMPLT_N")
	)
	(segment
		(start 139.637008 -64.818768)
		(end 139.24026 -65.215516)
		(width 0.127)
		(layer "In6.Cu")
		(net "FM_BIOS_POST_CMPLT_N")
	)
	(segment
		(start 193.834766 -80.965548)
		(end 193.675 -81.125314)
		(width 0.127)
		(layer "In6.Cu")
		(net "FM_BIOS_POST_CMPLT_N")
	)
	(segment
		(start 139.24026 -65.215516)
		(end 134.850632 -65.215516)
		(width 0.127)
		(layer "In6.Cu")
		(net "FM_BIOS_POST_CMPLT_N")
	)
	(segment
		(start 276.360636 -82.688938)
		(end 244.912642 -82.688938)
		(width 0.127)
		(layer "In6.Cu")
		(net "FM_BIOS_POST_CMPLT_N")
	)
	(segment
		(start 163.44392 -68.12534)
		(end 153.63952 -68.12534)
		(width 0.127)
		(layer "In6.Cu")
		(net "FM_BIOS_POST_CMPLT_N")
	)
	(segment
		(start 290.057078 -57.728358)
		(end 290.057078 -59.114182)
		(width 0.127)
		(layer "In6.Cu")
		(net "FM_BIOS_POST_CMPLT_N")
	)
	(segment
		(start 31.900368 -55.347616)
		(end 30.988 -54.435248)
		(width 0.127)
		(layer "In6.Cu")
		(net "FM_BIOS_POST_CMPLT_N")
	)
	(segment
		(start 286.163766 -63.007494)
		(end 286.163766 -72.885808)
		(width 0.127)
		(layer "In6.Cu")
		(net "FM_BIOS_POST_CMPLT_N")
	)
	(segment
		(start 198.8566 -81.647284)
		(end 198.174864 -80.965548)
		(width 0.127)
		(layer "In6.Cu")
		(net "FM_BIOS_POST_CMPLT_N")
	)
	(segment
		(start 308.379114 -41.900348)
		(end 307.975762 -41.900348)
		(width 0.127)
		(layer "In13.Cu")
		(net "FM_BIOS_POST_CMPLT_N")
	)
	(segment
		(start 302.900842 -46.975268)
		(end 299.803566 -46.975268)
		(width 0.127)
		(layer "In13.Cu")
		(net "FM_BIOS_POST_CMPLT_N")
	)
	(segment
		(start 297.6626 -48.513746)
		(end 296.754804 -49.421542)
		(width 0.127)
		(layer "In13.Cu")
		(net "FM_BIOS_POST_CMPLT_N")
	)
	(segment
		(start 298.265088 -48.513746)
		(end 297.6626 -48.513746)
		(width 0.127)
		(layer "In13.Cu")
		(net "FM_BIOS_POST_CMPLT_N")
	)
	(segment
		(start 307.975762 -41.900348)
		(end 302.900842 -46.975268)
		(width 0.127)
		(layer "In13.Cu")
		(net "FM_BIOS_POST_CMPLT_N")
	)
	(segment
		(start 299.803566 -46.975268)
		(end 298.265088 -48.513746)
		(width 0.127)
		(layer "In13.Cu")
		(net "FM_BIOS_POST_CMPLT_N")
	)
	(segment
		(start 290.057078 -54.692804)
		(end 290.057078 -57.728358)
		(width 0.127)
		(layer "In13.Cu")
		(net "FM_BIOS_POST_CMPLT_N")
	)
	(segment
		(start 295.32834 -49.421542)
		(end 290.057078 -54.692804)
		(width 0.127)
		(layer "In13.Cu")
		(net "FM_BIOS_POST_CMPLT_N")
	)
	(segment
		(start 296.754804 -49.421542)
		(end 295.32834 -49.421542)
		(width 0.127)
		(layer "In13.Cu")
		(net "FM_BIOS_POST_CMPLT_N")
	)
	(segment
		(start 304.999136 -41.900348)
		(end 306.963572 -41.900348)
		(width 0.12954)
		(layer "F.Cu")
		(net "FM_BIOS_POST_CMPLT_BMC_N")
	)
	(segment
		(start 182.155592 -111.375444)
		(end 182.555642 -110.975394)
		(width 0.12954)
		(layer "F.Cu")
		(net "FM_BIOS_POST_CMPLT_BMC_N")
	)
	(segment
		(start 304.143156 -41.044368)
		(end 304.999136 -41.900348)
		(width 0.12954)
		(layer "F.Cu")
		(net "FM_BIOS_POST_CMPLT_BMC_N")
	)
	(via
		(at 304.143156 -41.044368)
		(size 0.508)
		(drill 0.254)
		(layers "F.Cu" "B.Cu")
		(net "FM_BIOS_POST_CMPLT_BMC_N")
	)
	(via
		(at 318.31788 -114.645948)
		(size 0.508)
		(drill 0.254)
		(layers "F.Cu" "B.Cu")
		(net "FM_BIOS_POST_CMPLT_BMC_N")
	)
	(via
		(at 182.555642 -110.975394)
		(size 0.4572)
		(drill 0.254)
		(layers "F.Cu" "B.Cu")
		(net "FM_BIOS_POST_CMPLT_BMC_N")
	)
	(segment
		(start 306.39512 -45.933868)
		(end 304.143156 -43.681904)
		(width 0.127)
		(layer "In2.Cu")
		(net "FM_BIOS_POST_CMPLT_BMC_N")
	)
	(segment
		(start 318.31788 -82.673952)
		(end 314.543186 -78.899258)
		(width 0.127)
		(layer "In2.Cu")
		(net "FM_BIOS_POST_CMPLT_BMC_N")
	)
	(segment
		(start 307.98008 -60.318904)
		(end 305.54676 -57.885584)
		(width 0.127)
		(layer "In2.Cu")
		(net "FM_BIOS_POST_CMPLT_BMC_N")
	)
	(segment
		(start 304.143156 -43.681904)
		(end 304.143156 -41.044368)
		(width 0.127)
		(layer "In2.Cu")
		(net "FM_BIOS_POST_CMPLT_BMC_N")
	)
	(segment
		(start 306.39512 -54.237128)
		(end 306.39512 -45.933868)
		(width 0.127)
		(layer "In2.Cu")
		(net "FM_BIOS_POST_CMPLT_BMC_N")
	)
	(segment
		(start 305.54676 -57.885584)
		(end 305.54676 -55.085488)
		(width 0.127)
		(layer "In2.Cu")
		(net "FM_BIOS_POST_CMPLT_BMC_N")
	)
	(segment
		(start 314.543186 -78.899258)
		(end 310.518302 -69.182234)
		(width 0.127)
		(layer "In2.Cu")
		(net "FM_BIOS_POST_CMPLT_BMC_N")
	)
	(segment
		(start 318.31788 -114.645948)
		(end 318.31788 -82.673952)
		(width 0.127)
		(layer "In2.Cu")
		(net "FM_BIOS_POST_CMPLT_BMC_N")
	)
	(segment
		(start 310.518302 -69.182234)
		(end 309.27548 -67.939412)
		(width 0.127)
		(layer "In2.Cu")
		(net "FM_BIOS_POST_CMPLT_BMC_N")
	)
	(segment
		(start 305.54676 -55.085488)
		(end 306.39512 -54.237128)
		(width 0.127)
		(layer "In2.Cu")
		(net "FM_BIOS_POST_CMPLT_BMC_N")
	)
	(segment
		(start 309.27548 -67.939412)
		(end 309.27548 -67.351148)
		(width 0.127)
		(layer "In2.Cu")
		(net "FM_BIOS_POST_CMPLT_BMC_N")
	)
	(segment
		(start 307.98008 -66.055748)
		(end 307.98008 -60.318904)
		(width 0.127)
		(layer "In2.Cu")
		(net "FM_BIOS_POST_CMPLT_BMC_N")
	)
	(segment
		(start 309.27548 -67.351148)
		(end 307.98008 -66.055748)
		(width 0.127)
		(layer "In2.Cu")
		(net "FM_BIOS_POST_CMPLT_BMC_N")
	)
	(segment
		(start 269.690596 -116.881148)
		(end 268.001496 -118.570248)
		(width 0.127)
		(layer "In15.Cu")
		(net "FM_BIOS_POST_CMPLT_BMC_N")
	)
	(segment
		(start 205.45679 -111.173768)
		(end 198.68896 -111.173768)
		(width 0.127)
		(layer "In15.Cu")
		(net "FM_BIOS_POST_CMPLT_BMC_N")
	)
	(segment
		(start 186.72048 -113.147348)
		(end 184.0865 -113.147348)
		(width 0.127)
		(layer "In15.Cu")
		(net "FM_BIOS_POST_CMPLT_BMC_N")
	)
	(segment
		(start 198.0819 -110.566708)
		(end 192.99174 -110.566708)
		(width 0.127)
		(layer "In15.Cu")
		(net "FM_BIOS_POST_CMPLT_BMC_N")
	)
	(segment
		(start 182.9562 -111.375952)
		(end 182.555642 -110.975394)
		(width 0.127)
		(layer "In15.Cu")
		(net "FM_BIOS_POST_CMPLT_BMC_N")
	)
	(segment
		(start 232.845864 -107.635548)
		(end 217.388694 -107.635548)
		(width 0.127)
		(layer "In15.Cu")
		(net "FM_BIOS_POST_CMPLT_BMC_N")
	)
	(segment
		(start 249.72518 -118.570248)
		(end 245.83898 -114.684048)
		(width 0.127)
		(layer "In15.Cu")
		(net "FM_BIOS_POST_CMPLT_BMC_N")
	)
	(segment
		(start 183.75122 -112.395508)
		(end 183.5277 -112.171988)
		(width 0.127)
		(layer "In15.Cu")
		(net "FM_BIOS_POST_CMPLT_BMC_N")
	)
	(segment
		(start 183.5277 -112.171988)
		(end 183.11114 -112.171988)
		(width 0.127)
		(layer "In15.Cu")
		(net "FM_BIOS_POST_CMPLT_BMC_N")
	)
	(segment
		(start 268.001496 -118.570248)
		(end 249.72518 -118.570248)
		(width 0.127)
		(layer "In15.Cu")
		(net "FM_BIOS_POST_CMPLT_BMC_N")
	)
	(segment
		(start 208.841594 -110.207806)
		(end 206.422752 -110.207806)
		(width 0.127)
		(layer "In15.Cu")
		(net "FM_BIOS_POST_CMPLT_BMC_N")
	)
	(segment
		(start 198.68896 -111.173768)
		(end 198.0819 -110.566708)
		(width 0.127)
		(layer "In15.Cu")
		(net "FM_BIOS_POST_CMPLT_BMC_N")
	)
	(segment
		(start 245.83898 -114.684048)
		(end 239.894364 -114.684048)
		(width 0.127)
		(layer "In15.Cu")
		(net "FM_BIOS_POST_CMPLT_BMC_N")
	)
	(segment
		(start 214.8332 -106.6546)
		(end 214.122 -107.3658)
		(width 0.127)
		(layer "In15.Cu")
		(net "FM_BIOS_POST_CMPLT_BMC_N")
	)
	(segment
		(start 217.388694 -107.635548)
		(end 216.407746 -106.6546)
		(width 0.127)
		(layer "In15.Cu")
		(net "FM_BIOS_POST_CMPLT_BMC_N")
	)
	(segment
		(start 281.737308 -116.881148)
		(end 269.690596 -116.881148)
		(width 0.127)
		(layer "In15.Cu")
		(net "FM_BIOS_POST_CMPLT_BMC_N")
	)
	(segment
		(start 206.422752 -110.207806)
		(end 205.45679 -111.173768)
		(width 0.127)
		(layer "In15.Cu")
		(net "FM_BIOS_POST_CMPLT_BMC_N")
	)
	(segment
		(start 183.75122 -112.812068)
		(end 183.75122 -112.395508)
		(width 0.127)
		(layer "In15.Cu")
		(net "FM_BIOS_POST_CMPLT_BMC_N")
	)
	(segment
		(start 283.374846 -115.24361)
		(end 281.737308 -116.881148)
		(width 0.127)
		(layer "In15.Cu")
		(net "FM_BIOS_POST_CMPLT_BMC_N")
	)
	(segment
		(start 317.720218 -115.24361)
		(end 283.374846 -115.24361)
		(width 0.127)
		(layer "In15.Cu")
		(net "FM_BIOS_POST_CMPLT_BMC_N")
	)
	(segment
		(start 239.894364 -114.684048)
		(end 232.845864 -107.635548)
		(width 0.127)
		(layer "In15.Cu")
		(net "FM_BIOS_POST_CMPLT_BMC_N")
	)
	(segment
		(start 192.99174 -110.566708)
		(end 190.19012 -113.368328)
		(width 0.127)
		(layer "In15.Cu")
		(net "FM_BIOS_POST_CMPLT_BMC_N")
	)
	(segment
		(start 190.19012 -113.368328)
		(end 186.94146 -113.368328)
		(width 0.127)
		(layer "In15.Cu")
		(net "FM_BIOS_POST_CMPLT_BMC_N")
	)
	(segment
		(start 318.31788 -114.645948)
		(end 317.720218 -115.24361)
		(width 0.127)
		(layer "In15.Cu")
		(net "FM_BIOS_POST_CMPLT_BMC_N")
	)
	(segment
		(start 216.407746 -106.6546)
		(end 214.8332 -106.6546)
		(width 0.127)
		(layer "In15.Cu")
		(net "FM_BIOS_POST_CMPLT_BMC_N")
	)
	(segment
		(start 182.9562 -112.017048)
		(end 182.9562 -111.375952)
		(width 0.127)
		(layer "In15.Cu")
		(net "FM_BIOS_POST_CMPLT_BMC_N")
	)
	(segment
		(start 184.0865 -113.147348)
		(end 183.75122 -112.812068)
		(width 0.127)
		(layer "In15.Cu")
		(net "FM_BIOS_POST_CMPLT_BMC_N")
	)
	(segment
		(start 214.122 -107.3658)
		(end 211.6836 -107.3658)
		(width 0.127)
		(layer "In15.Cu")
		(net "FM_BIOS_POST_CMPLT_BMC_N")
	)
	(segment
		(start 211.6836 -107.3658)
		(end 208.841594 -110.207806)
		(width 0.127)
		(layer "In15.Cu")
		(net "FM_BIOS_POST_CMPLT_BMC_N")
	)
	(segment
		(start 186.94146 -113.368328)
		(end 186.72048 -113.147348)
		(width 0.127)
		(layer "In15.Cu")
		(net "FM_BIOS_POST_CMPLT_BMC_N")
	)
	(segment
		(start 183.11114 -112.171988)
		(end 182.9562 -112.017048)
		(width 0.127)
		(layer "In15.Cu")
		(net "FM_BIOS_POST_CMPLT_BMC_N")
	)
	(segment
		(start 325.287386 -51.120548)
		(end 325.74103 -50.666904)
		(width 0.0889)
		(layer "F.Cu")
		(net "FM_BIOS_IMAGE_SWAP_N")
	)
	(segment
		(start 324.658482 -51.120548)
		(end 325.287386 -51.120548)
		(width 0.0889)
		(layer "F.Cu")
		(net "FM_BIOS_IMAGE_SWAP_N")
	)
	(segment
		(start 326.911716 -50.757836)
		(end 327.140062 -50.757836)
		(width 0.0889)
		(layer "F.Cu")
		(net "FM_BIOS_IMAGE_SWAP_N")
	)
	(segment
		(start 327.4949 -50.451258)
		(end 327.829926 -50.451258)
		(width 0.0889)
		(layer "F.Cu")
		(net "FM_BIOS_IMAGE_SWAP_N")
	)
	(segment
		(start 326.775318 -50.666904)
		(end 326.911716 -50.757836)
		(width 0.0889)
		(layer "F.Cu")
		(net "FM_BIOS_IMAGE_SWAP_N")
	)
	(segment
		(start 325.74103 -50.666904)
		(end 326.775318 -50.666904)
		(width 0.0889)
		(layer "F.Cu")
		(net "FM_BIOS_IMAGE_SWAP_N")
	)
	(segment
		(start 327.140062 -50.757836)
		(end 327.4949 -50.451258)
		(width 0.0889)
		(layer "F.Cu")
		(net "FM_BIOS_IMAGE_SWAP_N")
	)
	(via
		(at 324.658482 -51.120548)
		(size 0.508)
		(drill 0.254)
		(layers "F.Cu" "B.Cu")
		(net "FM_BIOS_IMAGE_SWAP_N")
	)
	(via
		(at 314.04814 -51.171348)
		(size 0.508)
		(drill 0.254)
		(layers "F.Cu" "B.Cu")
		(net "FM_BIOS_IMAGE_SWAP_N")
	)
	(segment
		(start 314.04814 -51.171348)
		(end 314.1853 -51.308508)
		(width 0.12954)
		(layer "B.Cu")
		(net "FM_BIOS_IMAGE_SWAP_N")
	)
	(segment
		(start 314.1853 -51.308508)
		(end 314.573412 -51.308508)
		(width 0.12954)
		(layer "B.Cu")
		(net "FM_BIOS_IMAGE_SWAP_N")
	)
	(segment
		(start 314.573412 -51.308508)
		(end 314.710572 -51.171348)
		(width 0.12954)
		(layer "B.Cu")
		(net "FM_BIOS_IMAGE_SWAP_N")
	)
	(segment
		(start 323.540882 -50.002948)
		(end 315.26988 -50.002948)
		(width 0.127)
		(layer "In6.Cu")
		(net "FM_BIOS_IMAGE_SWAP_N")
	)
	(segment
		(start 315.26988 -50.002948)
		(end 314.10148 -51.171348)
		(width 0.127)
		(layer "In6.Cu")
		(net "FM_BIOS_IMAGE_SWAP_N")
	)
	(segment
		(start 324.658482 -51.120548)
		(end 323.540882 -50.002948)
		(width 0.127)
		(layer "In6.Cu")
		(net "FM_BIOS_IMAGE_SWAP_N")
	)
	(segment
		(start 314.10148 -51.171348)
		(end 314.04814 -51.171348)
		(width 0.127)
		(layer "In6.Cu")
		(net "FM_BIOS_IMAGE_SWAP_N")
	)
	(segment
		(start 348.723458 -56.543956)
		(end 350.66605 -58.486548)
		(width 0.127)
		(layer "In15.Cu")
		(net "FM_BIOS_IMAGE_SWAP_N")
	)
	(segment
		(start 401.74799 -38.273228)
		(end 427.896528 -38.273228)
		(width 0.127)
		(layer "In15.Cu")
		(net "FM_BIOS_IMAGE_SWAP_N")
	)
	(segment
		(start 366.419638 -50.663348)
		(end 371.75567 -50.663348)
		(width 0.127)
		(layer "In15.Cu")
		(net "FM_BIOS_IMAGE_SWAP_N")
	)
	(segment
		(start 365.204756 -51.87823)
		(end 366.419638 -50.663348)
		(width 0.127)
		(layer "In15.Cu")
		(net "FM_BIOS_IMAGE_SWAP_N")
	)
	(segment
		(start 429.16983 -36.999926)
		(end 429.170084 -36.999926)
		(width 0.127)
		(layer "In15.Cu")
		(net "FM_BIOS_IMAGE_SWAP_N")
	)
	(segment
		(start 354.3554 -59.627008)
		(end 363.179614 -59.627008)
		(width 0.127)
		(layer "In15.Cu")
		(net "FM_BIOS_IMAGE_SWAP_N")
	)
	(segment
		(start 330.08316 -52.205128)
		(end 330.42606 -52.205128)
		(width 0.127)
		(layer "In15.Cu")
		(net "FM_BIOS_IMAGE_SWAP_N")
	)
	(segment
		(start 326.37222 -50.643028)
		(end 327.4695 -51.740308)
		(width 0.127)
		(layer "In15.Cu")
		(net "FM_BIOS_IMAGE_SWAP_N")
	)
	(segment
		(start 329.61834 -51.740308)
		(end 330.08316 -52.205128)
		(width 0.127)
		(layer "In15.Cu")
		(net "FM_BIOS_IMAGE_SWAP_N")
	)
	(segment
		(start 330.89088 -51.740308)
		(end 331.23378 -51.740308)
		(width 0.127)
		(layer "In15.Cu")
		(net "FM_BIOS_IMAGE_SWAP_N")
	)
	(segment
		(start 331.23378 -51.740308)
		(end 331.80782 -52.314348)
		(width 0.127)
		(layer "In15.Cu")
		(net "FM_BIOS_IMAGE_SWAP_N")
	)
	(segment
		(start 343.80932 -57.932828)
		(end 345.198192 -56.543956)
		(width 0.127)
		(layer "In15.Cu")
		(net "FM_BIOS_IMAGE_SWAP_N")
	)
	(segment
		(start 345.198192 -56.543956)
		(end 348.723458 -56.543956)
		(width 0.127)
		(layer "In15.Cu")
		(net "FM_BIOS_IMAGE_SWAP_N")
	)
	(segment
		(start 327.4695 -51.740308)
		(end 329.61834 -51.740308)
		(width 0.127)
		(layer "In15.Cu")
		(net "FM_BIOS_IMAGE_SWAP_N")
	)
	(segment
		(start 331.80782 -52.314348)
		(end 332.70444 -52.314348)
		(width 0.127)
		(layer "In15.Cu")
		(net "FM_BIOS_IMAGE_SWAP_N")
	)
	(segment
		(start 335.70672 -57.932828)
		(end 343.80932 -57.932828)
		(width 0.127)
		(layer "In15.Cu")
		(net "FM_BIOS_IMAGE_SWAP_N")
	)
	(segment
		(start 371.75567 -50.663348)
		(end 375.97207 -46.446948)
		(width 0.127)
		(layer "In15.Cu")
		(net "FM_BIOS_IMAGE_SWAP_N")
	)
	(segment
		(start 334.55864 -54.168548)
		(end 334.55864 -56.784748)
		(width 0.127)
		(layer "In15.Cu")
		(net "FM_BIOS_IMAGE_SWAP_N")
	)
	(segment
		(start 334.55864 -56.784748)
		(end 335.70672 -57.932828)
		(width 0.127)
		(layer "In15.Cu")
		(net "FM_BIOS_IMAGE_SWAP_N")
	)
	(segment
		(start 332.70444 -52.314348)
		(end 334.55864 -54.168548)
		(width 0.127)
		(layer "In15.Cu")
		(net "FM_BIOS_IMAGE_SWAP_N")
	)
	(segment
		(start 363.179614 -59.627008)
		(end 363.567726 -59.238896)
		(width 0.127)
		(layer "In15.Cu")
		(net "FM_BIOS_IMAGE_SWAP_N")
	)
	(segment
		(start 325.136002 -50.643028)
		(end 326.37222 -50.643028)
		(width 0.127)
		(layer "In15.Cu")
		(net "FM_BIOS_IMAGE_SWAP_N")
	)
	(segment
		(start 393.57427 -46.446948)
		(end 401.74799 -38.273228)
		(width 0.127)
		(layer "In15.Cu")
		(net "FM_BIOS_IMAGE_SWAP_N")
	)
	(segment
		(start 363.567726 -59.238896)
		(end 365.483648 -59.238896)
		(width 0.127)
		(layer "In15.Cu")
		(net "FM_BIOS_IMAGE_SWAP_N")
	)
	(segment
		(start 324.658482 -51.120548)
		(end 325.136002 -50.643028)
		(width 0.127)
		(layer "In15.Cu")
		(net "FM_BIOS_IMAGE_SWAP_N")
	)
	(segment
		(start 367.0681 -56.313578)
		(end 365.204756 -54.450234)
		(width 0.127)
		(layer "In15.Cu")
		(net "FM_BIOS_IMAGE_SWAP_N")
	)
	(segment
		(start 365.204756 -54.450234)
		(end 365.204756 -51.87823)
		(width 0.127)
		(layer "In15.Cu")
		(net "FM_BIOS_IMAGE_SWAP_N")
	)
	(segment
		(start 350.66605 -58.486548)
		(end 353.21494 -58.486548)
		(width 0.127)
		(layer "In15.Cu")
		(net "FM_BIOS_IMAGE_SWAP_N")
	)
	(segment
		(start 353.21494 -58.486548)
		(end 354.3554 -59.627008)
		(width 0.127)
		(layer "In15.Cu")
		(net "FM_BIOS_IMAGE_SWAP_N")
	)
	(segment
		(start 427.896528 -38.273228)
		(end 429.16983 -36.999926)
		(width 0.127)
		(layer "In15.Cu")
		(net "FM_BIOS_IMAGE_SWAP_N")
	)
	(segment
		(start 367.0681 -57.654444)
		(end 367.0681 -56.313578)
		(width 0.127)
		(layer "In15.Cu")
		(net "FM_BIOS_IMAGE_SWAP_N")
	)
	(segment
		(start 365.483648 -59.238896)
		(end 367.0681 -57.654444)
		(width 0.127)
		(layer "In15.Cu")
		(net "FM_BIOS_IMAGE_SWAP_N")
	)
	(segment
		(start 375.97207 -46.446948)
		(end 393.57427 -46.446948)
		(width 0.127)
		(layer "In15.Cu")
		(net "FM_BIOS_IMAGE_SWAP_N")
	)
	(segment
		(start 330.42606 -52.205128)
		(end 330.89088 -51.740308)
		(width 0.127)
		(layer "In15.Cu")
		(net "FM_BIOS_IMAGE_SWAP_N")
	)
	(segment
		(start 326.711564 -50.23231)
		(end 327.13295 -49.950878)
		(width 0.0889)
		(layer "F.Cu")
		(net "FM_BIOS_DEBUG_EN_R_N")
	)
	(segment
		(start 326.460866 -50.23231)
		(end 326.711564 -50.23231)
		(width 0.0889)
		(layer "F.Cu")
		(net "FM_BIOS_DEBUG_EN_R_N")
	)
	(segment
		(start 323.689726 -50.485548)
		(end 325.232014 -50.485548)
		(width 0.0889)
		(layer "F.Cu")
		(net "FM_BIOS_DEBUG_EN_R_N")
	)
	(segment
		(start 327.13295 -49.950878)
		(end 327.41489 -49.950878)
		(width 0.0889)
		(layer "F.Cu")
		(net "FM_BIOS_DEBUG_EN_R_N")
	)
	(segment
		(start 325.520812 -50.19675)
		(end 326.340216 -50.19675)
		(width 0.0889)
		(layer "F.Cu")
		(net "FM_BIOS_DEBUG_EN_R_N")
	)
	(segment
		(start 326.340216 -50.19675)
		(end 326.460866 -50.23231)
		(width 0.0889)
		(layer "F.Cu")
		(net "FM_BIOS_DEBUG_EN_R_N")
	)
	(segment
		(start 323.365622 -50.809652)
		(end 323.689726 -50.485548)
		(width 0.0889)
		(layer "F.Cu")
		(net "FM_BIOS_DEBUG_EN_R_N")
	)
	(segment
		(start 325.232014 -50.485548)
		(end 325.520812 -50.19675)
		(width 0.0889)
		(layer "F.Cu")
		(net "FM_BIOS_DEBUG_EN_R_N")
	)
	(via
		(at 321.01282 -49.703228)
		(size 0.6604)
		(drill 0.3302)
		(layers "F.Cu" "B.Cu")
		(net "FM_BIOS_DEBUG_EN_R_N")
	)
	(via
		(at 323.365622 -50.809652)
		(size 0.508)
		(drill 0.254)
		(layers "F.Cu" "B.Cu")
		(net "FM_BIOS_DEBUG_EN_R_N")
	)
	(segment
		(start 321.01282 -49.703228)
		(end 321.8815 -50.571908)
		(width 0.12954)
		(layer "B.Cu")
		(net "FM_BIOS_DEBUG_EN_R_N")
	)
	(segment
		(start 323.365622 -49.981104)
		(end 323.326506 -49.941988)
		(width 0.12954)
		(layer "B.Cu")
		(net "FM_BIOS_DEBUG_EN_R_N")
	)
	(segment
		(start 321.8815 -50.571908)
		(end 323.127878 -50.571908)
		(width 0.12954)
		(layer "B.Cu")
		(net "FM_BIOS_DEBUG_EN_R_N")
	)
	(segment
		(start 323.127878 -50.571908)
		(end 323.365622 -50.809652)
		(width 0.12954)
		(layer "B.Cu")
		(net "FM_BIOS_DEBUG_EN_R_N")
	)
	(segment
		(start 323.365622 -50.809652)
		(end 323.365622 -49.981104)
		(width 0.12954)
		(layer "B.Cu")
		(net "FM_BIOS_DEBUG_EN_R_N")
	)
	(segment
		(start 184.555638 -115.375436)
		(end 184.955688 -115.775486)
		(width 0.12954)
		(layer "F.Cu")
		(net "FM_BIOS_DEBUG_EN_N")
	)
	(via
		(at 320.34988 -115.407948)
		(size 0.508)
		(drill 0.254)
		(layers "F.Cu" "B.Cu")
		(net "FM_BIOS_DEBUG_EN_N")
	)
	(via
		(at 184.955688 -115.775486)
		(size 0.4572)
		(drill 0.254)
		(layers "F.Cu" "B.Cu")
		(net "FM_BIOS_DEBUG_EN_N")
	)
	(via
		(at 306.492656 -40.373808)
		(size 0.508)
		(drill 0.254)
		(layers "F.Cu" "B.Cu")
		(net "FM_BIOS_DEBUG_EN_N")
	)
	(via
		(at 315.58738 -44.097448)
		(size 0.6604)
		(drill 0.3302)
		(layers "F.Cu" "B.Cu")
		(net "FM_BIOS_DEBUG_EN_N")
	)
	(segment
		(start 316.545722 -45.43679)
		(end 320.036444 -48.927512)
		(width 0.12954)
		(layer "B.Cu")
		(net "FM_BIOS_DEBUG_EN_N")
	)
	(segment
		(start 313.58332 -42.093388)
		(end 315.58738 -44.097448)
		(width 0.12954)
		(layer "B.Cu")
		(net "FM_BIOS_DEBUG_EN_N")
	)
	(segment
		(start 315.58738 -44.097448)
		(end 316.545722 -45.05579)
		(width 0.12954)
		(layer "B.Cu")
		(net "FM_BIOS_DEBUG_EN_N")
	)
	(segment
		(start 322.186046 -49.601628)
		(end 322.526406 -49.941988)
		(width 0.12954)
		(layer "B.Cu")
		(net "FM_BIOS_DEBUG_EN_N")
	)
	(segment
		(start 316.545722 -45.05579)
		(end 316.545722 -45.43679)
		(width 0.12954)
		(layer "B.Cu")
		(net "FM_BIOS_DEBUG_EN_N")
	)
	(segment
		(start 306.492656 -40.373808)
		(end 307.288946 -41.170098)
		(width 0.12954)
		(layer "B.Cu")
		(net "FM_BIOS_DEBUG_EN_N")
	)
	(segment
		(start 308.79161 -41.170098)
		(end 309.7149 -42.093388)
		(width 0.12954)
		(layer "B.Cu")
		(net "FM_BIOS_DEBUG_EN_N")
	)
	(segment
		(start 307.288946 -41.170098)
		(end 308.79161 -41.170098)
		(width 0.12954)
		(layer "B.Cu")
		(net "FM_BIOS_DEBUG_EN_N")
	)
	(segment
		(start 309.7149 -42.093388)
		(end 313.58332 -42.093388)
		(width 0.12954)
		(layer "B.Cu")
		(net "FM_BIOS_DEBUG_EN_N")
	)
	(segment
		(start 321.11188 -48.927512)
		(end 321.785996 -49.601628)
		(width 0.12954)
		(layer "B.Cu")
		(net "FM_BIOS_DEBUG_EN_N")
	)
	(segment
		(start 320.036444 -48.927512)
		(end 321.11188 -48.927512)
		(width 0.12954)
		(layer "B.Cu")
		(net "FM_BIOS_DEBUG_EN_N")
	)
	(segment
		(start 321.785996 -49.601628)
		(end 322.186046 -49.601628)
		(width 0.12954)
		(layer "B.Cu")
		(net "FM_BIOS_DEBUG_EN_N")
	)
	(segment
		(start 306.492656 -40.373808)
		(end 306.492656 -44.654724)
		(width 0.127)
		(layer "In2.Cu")
		(net "FM_BIOS_DEBUG_EN_N")
	)
	(segment
		(start 310.924702 -58.881518)
		(end 310.924702 -66.644012)
		(width 0.127)
		(layer "In2.Cu")
		(net "FM_BIOS_DEBUG_EN_N")
	)
	(segment
		(start 306.492656 -44.654724)
		(end 307.26888 -45.430948)
		(width 0.127)
		(layer "In2.Cu")
		(net "FM_BIOS_DEBUG_EN_N")
	)
	(segment
		(start 310.924702 -66.644012)
		(end 315.458856 -77.589888)
		(width 0.127)
		(layer "In2.Cu")
		(net "FM_BIOS_DEBUG_EN_N")
	)
	(segment
		(start 315.458856 -77.589888)
		(end 320.34988 -82.480912)
		(width 0.127)
		(layer "In2.Cu")
		(net "FM_BIOS_DEBUG_EN_N")
	)
	(segment
		(start 307.26888 -55.225696)
		(end 310.924702 -58.881518)
		(width 0.127)
		(layer "In2.Cu")
		(net "FM_BIOS_DEBUG_EN_N")
	)
	(segment
		(start 307.26888 -45.430948)
		(end 307.26888 -55.225696)
		(width 0.127)
		(layer "In2.Cu")
		(net "FM_BIOS_DEBUG_EN_N")
	)
	(segment
		(start 320.34988 -82.480912)
		(end 320.34988 -115.407948)
		(width 0.127)
		(layer "In2.Cu")
		(net "FM_BIOS_DEBUG_EN_N")
	)
	(segment
		(start 187.24118 -115.634008)
		(end 186.260994 -115.634008)
		(width 0.127)
		(layer "In15.Cu")
		(net "FM_BIOS_DEBUG_EN_N")
	)
	(segment
		(start 282.71343 -117.744748)
		(end 270.048736 -117.744748)
		(width 0.127)
		(layer "In15.Cu")
		(net "FM_BIOS_DEBUG_EN_N")
	)
	(segment
		(start 192.8876 -117.348)
		(end 192.114932 -117.348)
		(width 0.127)
		(layer "In15.Cu")
		(net "FM_BIOS_DEBUG_EN_N")
	)
	(segment
		(start 245.48084 -115.547648)
		(end 239.53597 -115.547648)
		(width 0.127)
		(layer "In15.Cu")
		(net "FM_BIOS_DEBUG_EN_N")
	)
	(segment
		(start 221.91726 -113.548668)
		(end 220.68282 -114.783108)
		(width 0.127)
		(layer "In15.Cu")
		(net "FM_BIOS_DEBUG_EN_N")
	)
	(segment
		(start 192.114932 -117.348)
		(end 190.20028 -115.433348)
		(width 0.127)
		(layer "In15.Cu")
		(net "FM_BIOS_DEBUG_EN_N")
	)
	(segment
		(start 190.20028 -115.433348)
		(end 187.44184 -115.433348)
		(width 0.127)
		(layer "In15.Cu")
		(net "FM_BIOS_DEBUG_EN_N")
	)
	(segment
		(start 199.4408 -117.605048)
		(end 198.49084 -118.555008)
		(width 0.127)
		(layer "In15.Cu")
		(net "FM_BIOS_DEBUG_EN_N")
	)
	(segment
		(start 220.68282 -114.783108)
		(end 216.14638 -114.783108)
		(width 0.127)
		(layer "In15.Cu")
		(net "FM_BIOS_DEBUG_EN_N")
	)
	(segment
		(start 283.60243 -116.855748)
		(end 282.71343 -117.744748)
		(width 0.127)
		(layer "In15.Cu")
		(net "FM_BIOS_DEBUG_EN_N")
	)
	(segment
		(start 195.1863 -118.176548)
		(end 194.81546 -118.547388)
		(width 0.127)
		(layer "In15.Cu")
		(net "FM_BIOS_DEBUG_EN_N")
	)
	(segment
		(start 201.5871 -117.605048)
		(end 199.4408 -117.605048)
		(width 0.127)
		(layer "In15.Cu")
		(net "FM_BIOS_DEBUG_EN_N")
	)
	(segment
		(start 194.086988 -118.547388)
		(end 192.8876 -117.348)
		(width 0.127)
		(layer "In15.Cu")
		(net "FM_BIOS_DEBUG_EN_N")
	)
	(segment
		(start 194.81546 -118.547388)
		(end 194.086988 -118.547388)
		(width 0.127)
		(layer "In15.Cu")
		(net "FM_BIOS_DEBUG_EN_N")
	)
	(segment
		(start 239.53597 -115.547648)
		(end 238.77143 -114.783108)
		(width 0.127)
		(layer "In15.Cu")
		(net "FM_BIOS_DEBUG_EN_N")
	)
	(segment
		(start 234.414568 -114.783108)
		(end 233.180128 -113.548668)
		(width 0.127)
		(layer "In15.Cu")
		(net "FM_BIOS_DEBUG_EN_N")
	)
	(segment
		(start 318.90208 -116.855748)
		(end 283.60243 -116.855748)
		(width 0.127)
		(layer "In15.Cu")
		(net "FM_BIOS_DEBUG_EN_N")
	)
	(segment
		(start 249.36704 -119.433848)
		(end 245.48084 -115.547648)
		(width 0.127)
		(layer "In15.Cu")
		(net "FM_BIOS_DEBUG_EN_N")
	)
	(segment
		(start 233.180128 -113.548668)
		(end 221.91726 -113.548668)
		(width 0.127)
		(layer "In15.Cu")
		(net "FM_BIOS_DEBUG_EN_N")
	)
	(segment
		(start 238.77143 -114.783108)
		(end 234.414568 -114.783108)
		(width 0.127)
		(layer "In15.Cu")
		(net "FM_BIOS_DEBUG_EN_N")
	)
	(segment
		(start 197.47992 -118.176548)
		(end 195.1863 -118.176548)
		(width 0.127)
		(layer "In15.Cu")
		(net "FM_BIOS_DEBUG_EN_N")
	)
	(segment
		(start 201.83094 -117.361208)
		(end 201.5871 -117.605048)
		(width 0.127)
		(layer "In15.Cu")
		(net "FM_BIOS_DEBUG_EN_N")
	)
	(segment
		(start 186.004454 -115.377468)
		(end 185.353706 -115.377468)
		(width 0.127)
		(layer "In15.Cu")
		(net "FM_BIOS_DEBUG_EN_N")
	)
	(segment
		(start 320.34988 -115.407948)
		(end 318.90208 -116.855748)
		(width 0.127)
		(layer "In15.Cu")
		(net "FM_BIOS_DEBUG_EN_N")
	)
	(segment
		(start 197.85838 -118.555008)
		(end 197.47992 -118.176548)
		(width 0.127)
		(layer "In15.Cu")
		(net "FM_BIOS_DEBUG_EN_N")
	)
	(segment
		(start 186.260994 -115.634008)
		(end 186.004454 -115.377468)
		(width 0.127)
		(layer "In15.Cu")
		(net "FM_BIOS_DEBUG_EN_N")
	)
	(segment
		(start 268.359636 -119.433848)
		(end 249.36704 -119.433848)
		(width 0.127)
		(layer "In15.Cu")
		(net "FM_BIOS_DEBUG_EN_N")
	)
	(segment
		(start 213.56828 -117.361208)
		(end 201.83094 -117.361208)
		(width 0.127)
		(layer "In15.Cu")
		(net "FM_BIOS_DEBUG_EN_N")
	)
	(segment
		(start 185.353706 -115.377468)
		(end 184.955688 -115.775486)
		(width 0.127)
		(layer "In15.Cu")
		(net "FM_BIOS_DEBUG_EN_N")
	)
	(segment
		(start 187.44184 -115.433348)
		(end 187.24118 -115.634008)
		(width 0.127)
		(layer "In15.Cu")
		(net "FM_BIOS_DEBUG_EN_N")
	)
	(segment
		(start 270.048736 -117.744748)
		(end 268.359636 -119.433848)
		(width 0.127)
		(layer "In15.Cu")
		(net "FM_BIOS_DEBUG_EN_N")
	)
	(segment
		(start 198.49084 -118.555008)
		(end 197.85838 -118.555008)
		(width 0.127)
		(layer "In15.Cu")
		(net "FM_BIOS_DEBUG_EN_N")
	)
	(segment
		(start 216.14638 -114.783108)
		(end 213.56828 -117.361208)
		(width 0.127)
		(layer "In15.Cu")
		(net "FM_BIOS_DEBUG_EN_N")
	)
	(segment
		(start 331.880718 -47.980346)
		(end 331.736446 -47.980346)
		(width 0.12954)
		(layer "F.Cu")
		(net "FM_BIOS_ADV_FUNCTIONS")
	)
	(segment
		(start 331.608176 -47.852076)
		(end 331.608176 -47.510446)
		(width 0.12954)
		(layer "F.Cu")
		(net "FM_BIOS_ADV_FUNCTIONS")
	)
	(segment
		(start 331.736446 -47.980346)
		(end 331.608176 -47.852076)
		(width 0.12954)
		(layer "F.Cu")
		(net "FM_BIOS_ADV_FUNCTIONS")
	)
	(via
		(at 331.880718 -47.980346)
		(size 0.4572)
		(drill 0.2032)
		(layers "F.Cu" "B.Cu")
		(net "FM_BIOS_ADV_FUNCTIONS")
	)
	(via
		(at 317.42888 -45.126148)
		(size 0.6604)
		(drill 0.3302)
		(layers "F.Cu" "B.Cu")
		(net "FM_BIOS_ADV_FUNCTIONS")
	)
	(segment
		(start 320.10096 -47.798228)
		(end 317.42888 -45.126148)
		(width 0.12954)
		(layer "B.Cu")
		(net "FM_BIOS_ADV_FUNCTIONS")
	)
	(segment
		(start 325.055738 -48.561752)
		(end 324.072504 -48.561752)
		(width 0.12954)
		(layer "B.Cu")
		(net "FM_BIOS_ADV_FUNCTIONS")
	)
	(segment
		(start 317.42888 -45.126148)
		(end 317.354712 -45.126148)
		(width 0.12954)
		(layer "B.Cu")
		(net "FM_BIOS_ADV_FUNCTIONS")
	)
	(segment
		(start 323.30898 -47.798228)
		(end 320.10096 -47.798228)
		(width 0.12954)
		(layer "B.Cu")
		(net "FM_BIOS_ADV_FUNCTIONS")
	)
	(segment
		(start 327.72985 -49.12106)
		(end 325.615046 -49.12106)
		(width 0.12954)
		(layer "B.Cu")
		(net "FM_BIOS_ADV_FUNCTIONS")
	)
	(segment
		(start 327.942702 -48.908208)
		(end 327.72985 -49.12106)
		(width 0.12954)
		(layer "B.Cu")
		(net "FM_BIOS_ADV_FUNCTIONS")
	)
	(segment
		(start 331.880718 -47.980346)
		(end 330.938378 -47.980346)
		(width 0.12954)
		(layer "B.Cu")
		(net "FM_BIOS_ADV_FUNCTIONS")
	)
	(segment
		(start 330.938378 -47.980346)
		(end 330.412598 -48.506126)
		(width 0.12954)
		(layer "B.Cu")
		(net "FM_BIOS_ADV_FUNCTIONS")
	)
	(segment
		(start 324.072504 -48.561752)
		(end 323.30898 -47.798228)
		(width 0.12954)
		(layer "B.Cu")
		(net "FM_BIOS_ADV_FUNCTIONS")
	)
	(segment
		(start 329.990958 -48.506126)
		(end 329.588876 -48.908208)
		(width 0.12954)
		(layer "B.Cu")
		(net "FM_BIOS_ADV_FUNCTIONS")
	)
	(segment
		(start 317.354712 -45.126148)
		(end 312.978292 -40.749728)
		(width 0.12954)
		(layer "B.Cu")
		(net "FM_BIOS_ADV_FUNCTIONS")
	)
	(segment
		(start 312.978292 -40.749728)
		(end 312.978292 -39.794688)
		(width 0.12954)
		(layer "B.Cu")
		(net "FM_BIOS_ADV_FUNCTIONS")
	)
	(segment
		(start 329.588876 -48.908208)
		(end 327.942702 -48.908208)
		(width 0.12954)
		(layer "B.Cu")
		(net "FM_BIOS_ADV_FUNCTIONS")
	)
	(segment
		(start 312.978292 -38.763448)
		(end 312.978292 -39.794688)
		(width 0.12954)
		(layer "B.Cu")
		(net "FM_BIOS_ADV_FUNCTIONS")
	)
	(segment
		(start 325.615046 -49.12106)
		(end 325.055738 -48.561752)
		(width 0.12954)
		(layer "B.Cu")
		(net "FM_BIOS_ADV_FUNCTIONS")
	)
	(segment
		(start 330.412598 -48.506126)
		(end 329.990958 -48.506126)
		(width 0.12954)
		(layer "B.Cu")
		(net "FM_BIOS_ADV_FUNCTIONS")
	)
	(segment
		(start 174.155608 -118.575328)
		(end 173.755558 -118.975378)
		(width 0.12954)
		(layer "F.Cu")
		(net "FM_AUX_SW_EN")
	)
	(segment
		(start 171.50588 -129.866898)
		(end 171.50588 -129.250948)
		(width 0.12954)
		(layer "F.Cu")
		(net "FM_AUX_SW_EN")
	)
	(via
		(at 173.755558 -118.975378)
		(size 0.4572)
		(drill 0.254)
		(layers "F.Cu" "B.Cu")
		(net "FM_AUX_SW_EN")
	)
	(via
		(at 171.50588 -129.250948)
		(size 0.508)
		(drill 0.254)
		(layers "F.Cu" "B.Cu")
		(net "FM_AUX_SW_EN")
	)
	(segment
		(start 173.35754 -121.603008)
		(end 173.35754 -119.373396)
		(width 0.127)
		(layer "In2.Cu")
		(net "FM_AUX_SW_EN")
	)
	(segment
		(start 173.16958 -121.790968)
		(end 173.35754 -121.603008)
		(width 0.127)
		(layer "In2.Cu")
		(net "FM_AUX_SW_EN")
	)
	(segment
		(start 170.77182 -122.73788)
		(end 171.718732 -121.790968)
		(width 0.127)
		(layer "In2.Cu")
		(net "FM_AUX_SW_EN")
	)
	(segment
		(start 173.35754 -119.373396)
		(end 173.755558 -118.975378)
		(width 0.127)
		(layer "In2.Cu")
		(net "FM_AUX_SW_EN")
	)
	(segment
		(start 171.718732 -121.790968)
		(end 173.16958 -121.790968)
		(width 0.127)
		(layer "In2.Cu")
		(net "FM_AUX_SW_EN")
	)
	(segment
		(start 171.50588 -129.250948)
		(end 170.77182 -128.516888)
		(width 0.127)
		(layer "In2.Cu")
		(net "FM_AUX_SW_EN")
	)
	(segment
		(start 170.77182 -128.516888)
		(end 170.77182 -122.73788)
		(width 0.127)
		(layer "In2.Cu")
		(net "FM_AUX_SW_EN")
	)
	(segment
		(start 326.832214 -46.75378)
		(end 327.142348 -46.75378)
		(width 0.0889)
		(layer "F.Cu")
		(net "FM_ADR_TRIGGER_R_N")
	)
	(segment
		(start 327.384664 -46.544484)
		(end 327.479914 -46.449234)
		(width 0.0889)
		(layer "F.Cu")
		(net "FM_ADR_TRIGGER_R_N")
	)
	(segment
		(start 323.371972 -46.465998)
		(end 323.746622 -46.091348)
		(width 0.0889)
		(layer "F.Cu")
		(net "FM_ADR_TRIGGER_R_N")
	)
	(segment
		(start 323.746622 -46.091348)
		(end 325.016622 -46.091348)
		(width 0.0889)
		(layer "F.Cu")
		(net "FM_ADR_TRIGGER_R_N")
	)
	(segment
		(start 318.862964 -46.465998)
		(end 322.575174 -46.465998)
		(width 0.12954)
		(layer "F.Cu")
		(net "FM_ADR_TRIGGER_R_N")
	)
	(segment
		(start 316.761114 -44.364148)
		(end 317.288164 -44.891198)
		(width 0.12954)
		(layer "F.Cu")
		(net "FM_ADR_TRIGGER_R_N")
	)
	(segment
		(start 315.505084 -44.364148)
		(end 316.761114 -44.364148)
		(width 0.12954)
		(layer "F.Cu")
		(net "FM_ADR_TRIGGER_R_N")
	)
	(segment
		(start 315.05906 -44.810172)
		(end 315.505084 -44.364148)
		(width 0.12954)
		(layer "F.Cu")
		(net "FM_ADR_TRIGGER_R_N")
	)
	(segment
		(start 322.575174 -46.465998)
		(end 323.371972 -46.465998)
		(width 0.0889)
		(layer "F.Cu")
		(net "FM_ADR_TRIGGER_R_N")
	)
	(segment
		(start 325.58609 -46.660816)
		(end 326.717914 -46.660816)
		(width 0.0889)
		(layer "F.Cu")
		(net "FM_ADR_TRIGGER_R_N")
	)
	(segment
		(start 325.016622 -46.091348)
		(end 325.58609 -46.660816)
		(width 0.0889)
		(layer "F.Cu")
		(net "FM_ADR_TRIGGER_R_N")
	)
	(segment
		(start 313.515756 -45.202348)
		(end 313.907932 -44.810172)
		(width 0.12954)
		(layer "F.Cu")
		(net "FM_ADR_TRIGGER_R_N")
	)
	(segment
		(start 313.907932 -44.810172)
		(end 315.05906 -44.810172)
		(width 0.12954)
		(layer "F.Cu")
		(net "FM_ADR_TRIGGER_R_N")
	)
	(segment
		(start 327.479914 -46.449234)
		(end 327.829926 -46.449234)
		(width 0.0889)
		(layer "F.Cu")
		(net "FM_ADR_TRIGGER_R_N")
	)
	(segment
		(start 326.82815 -46.750986)
		(end 326.832214 -46.75378)
		(width 0.0889)
		(layer "F.Cu")
		(net "FM_ADR_TRIGGER_R_N")
	)
	(segment
		(start 312.843672 -45.202348)
		(end 313.515756 -45.202348)
		(width 0.12954)
		(layer "F.Cu")
		(net "FM_ADR_TRIGGER_R_N")
	)
	(segment
		(start 326.717914 -46.660816)
		(end 326.82815 -46.750986)
		(width 0.0889)
		(layer "F.Cu")
		(net "FM_ADR_TRIGGER_R_N")
	)
	(segment
		(start 317.288164 -44.891198)
		(end 318.862964 -46.465998)
		(width 0.12954)
		(layer "F.Cu")
		(net "FM_ADR_TRIGGER_R_N")
	)
	(segment
		(start 327.142348 -46.75378)
		(end 327.384664 -46.544484)
		(width 0.0889)
		(layer "F.Cu")
		(net "FM_ADR_TRIGGER_R_N")
	)
	(via
		(at 317.288164 -44.891198)
		(size 0.762)
		(drill 0.381)
		(layers "F.Cu" "B.Cu")
		(net "FM_ADR_TRIGGER_R_N")
	)
	(segment
		(start 312.043572 -45.202348)
		(end 311.427622 -45.202348)
		(width 0.12954)
		(layer "F.Cu")
		(net "FM_ADR_TRIGGER_N")
	)
	(segment
		(start 183.755538 -108.975398)
		(end 184.155588 -108.575348)
		(width 0.12954)
		(layer "F.Cu")
		(net "FM_ADR_TRIGGER_N")
	)
	(via
		(at 311.427622 -45.202348)
		(size 0.508)
		(drill 0.254)
		(layers "F.Cu" "B.Cu")
		(net "FM_ADR_TRIGGER_N")
	)
	(via
		(at 323.14388 -110.327948)
		(size 0.508)
		(drill 0.254)
		(layers "F.Cu" "B.Cu")
		(net "FM_ADR_TRIGGER_N")
	)
	(via
		(at 184.155588 -108.575348)
		(size 0.4572)
		(drill 0.254)
		(layers "F.Cu" "B.Cu")
		(net "FM_ADR_TRIGGER_N")
	)
	(segment
		(start 184.155588 -108.575348)
		(end 184.554368 -108.176568)
		(width 0.12954)
		(layer "B.Cu")
		(net "FM_ADR_TRIGGER_N")
	)
	(segment
		(start 193.20383 -103.905304)
		(end 193.20383 -103.685848)
		(width 0.12954)
		(layer "B.Cu")
		(net "FM_ADR_TRIGGER_N")
	)
	(segment
		(start 184.554368 -108.176568)
		(end 188.932566 -108.176568)
		(width 0.12954)
		(layer "B.Cu")
		(net "FM_ADR_TRIGGER_N")
	)
	(segment
		(start 188.932566 -108.176568)
		(end 193.20383 -103.905304)
		(width 0.12954)
		(layer "B.Cu")
		(net "FM_ADR_TRIGGER_N")
	)
	(segment
		(start 312.74258 -66.383916)
		(end 315.603636 -73.291192)
		(width 0.127)
		(layer "In2.Cu")
		(net "FM_ADR_TRIGGER_N")
	)
	(segment
		(start 312.74258 -64.68237)
		(end 312.74258 -66.383916)
		(width 0.127)
		(layer "In2.Cu")
		(net "FM_ADR_TRIGGER_N")
	)
	(segment
		(start 322.7197 -109.903768)
		(end 323.14388 -110.327948)
		(width 0.127)
		(layer "In2.Cu")
		(net "FM_ADR_TRIGGER_N")
	)
	(segment
		(start 310.19496 -46.43501)
		(end 310.19496 -55.635652)
		(width 0.127)
		(layer "In2.Cu")
		(net "FM_ADR_TRIGGER_N")
	)
	(segment
		(start 310.19496 -55.635652)
		(end 313.4233 -58.863992)
		(width 0.127)
		(layer "In2.Cu")
		(net "FM_ADR_TRIGGER_N")
	)
	(segment
		(start 311.427622 -45.202348)
		(end 310.19496 -46.43501)
		(width 0.127)
		(layer "In2.Cu")
		(net "FM_ADR_TRIGGER_N")
	)
	(segment
		(start 313.4233 -58.863992)
		(end 313.4233 -64.00165)
		(width 0.127)
		(layer "In2.Cu")
		(net "FM_ADR_TRIGGER_N")
	)
	(segment
		(start 313.4233 -64.00165)
		(end 312.74258 -64.68237)
		(width 0.127)
		(layer "In2.Cu")
		(net "FM_ADR_TRIGGER_N")
	)
	(segment
		(start 322.7197 -80.407256)
		(end 322.7197 -109.903768)
		(width 0.127)
		(layer "In2.Cu")
		(net "FM_ADR_TRIGGER_N")
	)
	(segment
		(start 315.603636 -73.291192)
		(end 322.7197 -80.407256)
		(width 0.127)
		(layer "In2.Cu")
		(net "FM_ADR_TRIGGER_N")
	)
	(segment
		(start 266.79017 -115.649248)
		(end 268.47927 -113.960148)
		(width 0.127)
		(layer "In15.Cu")
		(net "FM_ADR_TRIGGER_N")
	)
	(segment
		(start 241.438938 -105.666286)
		(end 251.4219 -115.649248)
		(width 0.127)
		(layer "In15.Cu")
		(net "FM_ADR_TRIGGER_N")
	)
	(segment
		(start 221.48546 -101.77526)
		(end 222.108268 -102.398068)
		(width 0.127)
		(layer "In15.Cu")
		(net "FM_ADR_TRIGGER_N")
	)
	(segment
		(start 207.2894 -103.139748)
		(end 208.442052 -101.987096)
		(width 0.127)
		(layer "In15.Cu")
		(net "FM_ADR_TRIGGER_N")
	)
	(segment
		(start 219.24772 -101.77526)
		(end 221.48546 -101.77526)
		(width 0.127)
		(layer "In15.Cu")
		(net "FM_ADR_TRIGGER_N")
	)
	(segment
		(start 184.549288 -108.969048)
		(end 188.1759 -108.969048)
		(width 0.127)
		(layer "In15.Cu")
		(net "FM_ADR_TRIGGER_N")
	)
	(segment
		(start 208.442052 -101.987096)
		(end 219.035884 -101.987096)
		(width 0.127)
		(layer "In15.Cu")
		(net "FM_ADR_TRIGGER_N")
	)
	(segment
		(start 231.816656 -102.398068)
		(end 235.084874 -105.666286)
		(width 0.127)
		(layer "In15.Cu")
		(net "FM_ADR_TRIGGER_N")
	)
	(segment
		(start 268.47927 -113.960148)
		(end 279.969468 -113.960148)
		(width 0.127)
		(layer "In15.Cu")
		(net "FM_ADR_TRIGGER_N")
	)
	(segment
		(start 235.084874 -105.666286)
		(end 241.438938 -105.666286)
		(width 0.127)
		(layer "In15.Cu")
		(net "FM_ADR_TRIGGER_N")
	)
	(segment
		(start 282.956508 -110.973108)
		(end 322.49872 -110.973108)
		(width 0.127)
		(layer "In15.Cu")
		(net "FM_ADR_TRIGGER_N")
	)
	(segment
		(start 251.4219 -115.649248)
		(end 266.79017 -115.649248)
		(width 0.127)
		(layer "In15.Cu")
		(net "FM_ADR_TRIGGER_N")
	)
	(segment
		(start 184.155588 -108.575348)
		(end 184.549288 -108.969048)
		(width 0.127)
		(layer "In15.Cu")
		(net "FM_ADR_TRIGGER_N")
	)
	(segment
		(start 279.969468 -113.960148)
		(end 282.956508 -110.973108)
		(width 0.127)
		(layer "In15.Cu")
		(net "FM_ADR_TRIGGER_N")
	)
	(segment
		(start 222.108268 -102.398068)
		(end 231.816656 -102.398068)
		(width 0.127)
		(layer "In15.Cu")
		(net "FM_ADR_TRIGGER_N")
	)
	(segment
		(start 194.0052 -103.139748)
		(end 207.2894 -103.139748)
		(width 0.127)
		(layer "In15.Cu")
		(net "FM_ADR_TRIGGER_N")
	)
	(segment
		(start 188.1759 -108.969048)
		(end 194.0052 -103.139748)
		(width 0.127)
		(layer "In15.Cu")
		(net "FM_ADR_TRIGGER_N")
	)
	(segment
		(start 219.035884 -101.987096)
		(end 219.24772 -101.77526)
		(width 0.127)
		(layer "In15.Cu")
		(net "FM_ADR_TRIGGER_N")
	)
	(segment
		(start 322.49872 -110.973108)
		(end 323.14388 -110.327948)
		(width 0.127)
		(layer "In15.Cu")
		(net "FM_ADR_TRIGGER_N")
	)
	(segment
		(start 193.20383 -102.415848)
		(end 191.643 -102.415848)
		(width 0.12954)
		(layer "F.Cu")
		(net "FM_ADR_MODE1_R")
	)
	(segment
		(start 190.50508 -106.860848)
		(end 187.24118 -106.860848)
		(width 0.12954)
		(layer "F.Cu")
		(net "FM_ADR_MODE1_R")
	)
	(segment
		(start 191.35979 -102.699058)
		(end 191.35979 -106.006138)
		(width 0.12954)
		(layer "F.Cu")
		(net "FM_ADR_MODE1_R")
	)
	(segment
		(start 191.643 -102.415848)
		(end 191.35979 -102.699058)
		(width 0.12954)
		(layer "F.Cu")
		(net "FM_ADR_MODE1_R")
	)
	(segment
		(start 191.35979 -106.006138)
		(end 190.50508 -106.860848)
		(width 0.12954)
		(layer "F.Cu")
		(net "FM_ADR_MODE1_R")
	)
	(segment
		(start 187.24118 -106.860848)
		(end 186.955684 -106.575352)
		(width 0.12954)
		(layer "F.Cu")
		(net "FM_ADR_MODE1_R")
	)
	(via
		(at 190.50508 -106.860848)
		(size 0.762)
		(drill 0.381)
		(layers "F.Cu" "B.Cu")
		(net "FM_ADR_MODE1_R")
	)
	(segment
		(start 328.244962 -45.351192)
		(end 328.244962 -44.948602)
		(width 0.12954)
		(layer "F.Cu")
		(net "FM_ADR_MODE1")
	)
	(segment
		(start 328.371962 -45.478192)
		(end 328.244962 -45.351192)
		(width 0.12954)
		(layer "F.Cu")
		(net "FM_ADR_MODE1")
	)
	(segment
		(start 328.551794 -45.478192)
		(end 328.371962 -45.478192)
		(width 0.12954)
		(layer "F.Cu")
		(net "FM_ADR_MODE1")
	)
	(segment
		(start 194.00393 -102.415848)
		(end 194.61353 -102.415848)
		(width 0.12954)
		(layer "F.Cu")
		(net "FM_ADR_MODE1")
	)
	(via
		(at 319.07988 -110.327948)
		(size 0.508)
		(drill 0.254)
		(layers "F.Cu" "B.Cu")
		(net "FM_ADR_MODE1")
	)
	(via
		(at 328.551794 -45.478192)
		(size 0.4572)
		(drill 0.2032)
		(layers "F.Cu" "B.Cu")
		(net "FM_ADR_MODE1")
	)
	(via
		(at 194.61353 -102.415848)
		(size 0.508)
		(drill 0.254)
		(layers "F.Cu" "B.Cu")
		(net "FM_ADR_MODE1")
	)
	(via
		(at 305.52644 -30.579568)
		(size 0.508)
		(drill 0.254)
		(layers "F.Cu" "B.Cu")
		(net "FM_ADR_MODE1")
	)
	(segment
		(start 308.85384 -29.80436)
		(end 309.55234 -29.10586)
		(width 0.12954)
		(layer "B.Cu")
		(net "FM_ADR_MODE1")
	)
	(segment
		(start 323.889878 -42.701718)
		(end 326.009254 -44.821094)
		(width 0.12954)
		(layer "B.Cu")
		(net "FM_ADR_MODE1")
	)
	(segment
		(start 327.894696 -44.821094)
		(end 328.551794 -45.478192)
		(width 0.12954)
		(layer "B.Cu")
		(net "FM_ADR_MODE1")
	)
	(segment
		(start 310.22036 -29.10586)
		(end 310.4134 -29.2989)
		(width 0.12954)
		(layer "B.Cu")
		(net "FM_ADR_MODE1")
	)
	(segment
		(start 317.469774 -38.458394)
		(end 317.923672 -38.458394)
		(width 0.12954)
		(layer "B.Cu")
		(net "FM_ADR_MODE1")
	)
	(segment
		(start 322.05803 -42.263568)
		(end 322.49618 -42.701718)
		(width 0.12954)
		(layer "B.Cu")
		(net "FM_ADR_MODE1")
	)
	(segment
		(start 316.228222 -36.762944)
		(end 316.46622 -37.000942)
		(width 0.12954)
		(layer "B.Cu")
		(net "FM_ADR_MODE1")
	)
	(segment
		(start 305.52644 -30.579568)
		(end 306.29352 -31.346648)
		(width 0.12954)
		(layer "B.Cu")
		(net "FM_ADR_MODE1")
	)
	(segment
		(start 319.505076 -40.039798)
		(end 319.505076 -40.315134)
		(width 0.12954)
		(layer "B.Cu")
		(net "FM_ADR_MODE1")
	)
	(segment
		(start 316.46622 -37.45484)
		(end 317.469774 -38.458394)
		(width 0.12954)
		(layer "B.Cu")
		(net "FM_ADR_MODE1")
	)
	(segment
		(start 322.49618 -42.701718)
		(end 323.889878 -42.701718)
		(width 0.12954)
		(layer "B.Cu")
		(net "FM_ADR_MODE1")
	)
	(segment
		(start 320.9671 -42.263568)
		(end 322.05803 -42.263568)
		(width 0.12954)
		(layer "B.Cu")
		(net "FM_ADR_MODE1")
	)
	(segment
		(start 319.505076 -40.315134)
		(end 320.32448 -41.134538)
		(width 0.12954)
		(layer "B.Cu")
		(net "FM_ADR_MODE1")
	)
	(segment
		(start 306.29352 -31.346648)
		(end 307.49748 -31.346648)
		(width 0.12954)
		(layer "B.Cu")
		(net "FM_ADR_MODE1")
	)
	(segment
		(start 309.55234 -29.10586)
		(end 310.22036 -29.10586)
		(width 0.12954)
		(layer "B.Cu")
		(net "FM_ADR_MODE1")
	)
	(segment
		(start 310.4134 -29.2989)
		(end 310.4134 -30.348428)
		(width 0.12954)
		(layer "B.Cu")
		(net "FM_ADR_MODE1")
	)
	(segment
		(start 310.642 -30.577028)
		(end 312.76417 -30.577028)
		(width 0.12954)
		(layer "B.Cu")
		(net "FM_ADR_MODE1")
	)
	(segment
		(start 326.009254 -44.821094)
		(end 327.894696 -44.821094)
		(width 0.12954)
		(layer "B.Cu")
		(net "FM_ADR_MODE1")
	)
	(segment
		(start 308.84368 -30.724348)
		(end 307.763672 -30.724348)
		(width 0.12954)
		(layer "B.Cu")
		(net "FM_ADR_MODE1")
	)
	(segment
		(start 317.923672 -38.458394)
		(end 319.505076 -40.039798)
		(width 0.12954)
		(layer "B.Cu")
		(net "FM_ADR_MODE1")
	)
	(segment
		(start 316.46622 -37.000942)
		(end 316.46622 -37.45484)
		(width 0.12954)
		(layer "B.Cu")
		(net "FM_ADR_MODE1")
	)
	(segment
		(start 310.4134 -30.348428)
		(end 310.642 -30.577028)
		(width 0.12954)
		(layer "B.Cu")
		(net "FM_ADR_MODE1")
	)
	(segment
		(start 308.85384 -30.734508)
		(end 308.85384 -29.80436)
		(width 0.12954)
		(layer "B.Cu")
		(net "FM_ADR_MODE1")
	)
	(segment
		(start 320.32448 -41.134538)
		(end 320.32448 -41.620948)
		(width 0.12954)
		(layer "B.Cu")
		(net "FM_ADR_MODE1")
	)
	(segment
		(start 316.228222 -34.04108)
		(end 316.228222 -36.762944)
		(width 0.12954)
		(layer "B.Cu")
		(net "FM_ADR_MODE1")
	)
	(segment
		(start 307.763672 -31.080456)
		(end 307.763672 -30.724348)
		(width 0.12954)
		(layer "B.Cu")
		(net "FM_ADR_MODE1")
	)
	(segment
		(start 307.49748 -31.346648)
		(end 307.763672 -31.080456)
		(width 0.12954)
		(layer "B.Cu")
		(net "FM_ADR_MODE1")
	)
	(segment
		(start 312.76417 -30.577028)
		(end 316.228222 -34.04108)
		(width 0.12954)
		(layer "B.Cu")
		(net "FM_ADR_MODE1")
	)
	(segment
		(start 308.85384 -30.734508)
		(end 308.84368 -30.724348)
		(width 0.12954)
		(layer "B.Cu")
		(net "FM_ADR_MODE1")
	)
	(segment
		(start 320.32448 -41.620948)
		(end 320.9671 -42.263568)
		(width 0.12954)
		(layer "B.Cu")
		(net "FM_ADR_MODE1")
	)
	(segment
		(start 305.87696 -55.418228)
		(end 306.76596 -54.529228)
		(width 0.127)
		(layer "In2.Cu")
		(net "FM_ADR_MODE1")
	)
	(segment
		(start 305.87696 -57.748678)
		(end 305.87696 -55.418228)
		(width 0.127)
		(layer "In2.Cu")
		(net "FM_ADR_MODE1")
	)
	(segment
		(start 306.76596 -54.529228)
		(end 306.76596 -45.540168)
		(width 0.127)
		(layer "In2.Cu")
		(net "FM_ADR_MODE1")
	)
	(segment
		(start 308.322726 -60.194444)
		(end 305.87696 -57.748678)
		(width 0.127)
		(layer "In2.Cu")
		(net "FM_ADR_MODE1")
	)
	(segment
		(start 306.76596 -45.540168)
		(end 305.52644 -44.300648)
		(width 0.127)
		(layer "In2.Cu")
		(net "FM_ADR_MODE1")
	)
	(segment
		(start 319.07988 -82.846672)
		(end 314.737242 -78.504034)
		(width 0.127)
		(layer "In2.Cu")
		(net "FM_ADR_MODE1")
	)
	(segment
		(start 310.79821 -68.994782)
		(end 309.68188 -67.878452)
		(width 0.127)
		(layer "In2.Cu")
		(net "FM_ADR_MODE1")
	)
	(segment
		(start 308.322726 -65.915794)
		(end 308.322726 -60.194444)
		(width 0.127)
		(layer "In2.Cu")
		(net "FM_ADR_MODE1")
	)
	(segment
		(start 309.68188 -67.274948)
		(end 308.322726 -65.915794)
		(width 0.127)
		(layer "In2.Cu")
		(net "FM_ADR_MODE1")
	)
	(segment
		(start 319.07988 -110.327948)
		(end 319.07988 -82.846672)
		(width 0.127)
		(layer "In2.Cu")
		(net "FM_ADR_MODE1")
	)
	(segment
		(start 314.737242 -78.504034)
		(end 310.79821 -68.994782)
		(width 0.127)
		(layer "In2.Cu")
		(net "FM_ADR_MODE1")
	)
	(segment
		(start 309.68188 -67.878452)
		(end 309.68188 -67.274948)
		(width 0.127)
		(layer "In2.Cu")
		(net "FM_ADR_MODE1")
	)
	(segment
		(start 305.52644 -44.300648)
		(end 305.52644 -30.579568)
		(width 0.127)
		(layer "In2.Cu")
		(net "FM_ADR_MODE1")
	)
	(segment
		(start 235.222034 -105.336086)
		(end 231.369616 -101.483668)
		(width 0.127)
		(layer "In15.Cu")
		(net "FM_ADR_MODE1")
	)
	(segment
		(start 279.67813 -113.629948)
		(end 268.342364 -113.629948)
		(width 0.127)
		(layer "In15.Cu")
		(net "FM_ADR_MODE1")
	)
	(segment
		(start 219.117672 -100.59162)
		(end 210.443572 -100.59162)
		(width 0.127)
		(layer "In15.Cu")
		(net "FM_ADR_MODE1")
	)
	(segment
		(start 221.634812 -100.75164)
		(end 219.277692 -100.75164)
		(width 0.127)
		(layer "In15.Cu")
		(net "FM_ADR_MODE1")
	)
	(segment
		(start 219.277692 -100.75164)
		(end 219.117672 -100.59162)
		(width 0.127)
		(layer "In15.Cu")
		(net "FM_ADR_MODE1")
	)
	(segment
		(start 268.342364 -113.629948)
		(end 266.653264 -115.319048)
		(width 0.127)
		(layer "In15.Cu")
		(net "FM_ADR_MODE1")
	)
	(segment
		(start 194.74053 -101.727)
		(end 194.61353 -101.854)
		(width 0.127)
		(layer "In15.Cu")
		(net "FM_ADR_MODE1")
	)
	(segment
		(start 222.36684 -101.483668)
		(end 221.634812 -100.75164)
		(width 0.127)
		(layer "In15.Cu")
		(net "FM_ADR_MODE1")
	)
	(segment
		(start 210.443572 -100.59162)
		(end 210.12658 -100.274628)
		(width 0.127)
		(layer "In15.Cu")
		(net "FM_ADR_MODE1")
	)
	(segment
		(start 266.653264 -115.319048)
		(end 251.55906 -115.319048)
		(width 0.127)
		(layer "In15.Cu")
		(net "FM_ADR_MODE1")
	)
	(segment
		(start 208.0768 -100.274628)
		(end 206.624428 -101.727)
		(width 0.127)
		(layer "In15.Cu")
		(net "FM_ADR_MODE1")
	)
	(segment
		(start 282.98013 -110.327948)
		(end 279.67813 -113.629948)
		(width 0.127)
		(layer "In15.Cu")
		(net "FM_ADR_MODE1")
	)
	(segment
		(start 210.12658 -100.274628)
		(end 208.0768 -100.274628)
		(width 0.127)
		(layer "In15.Cu")
		(net "FM_ADR_MODE1")
	)
	(segment
		(start 231.369616 -101.483668)
		(end 222.36684 -101.483668)
		(width 0.127)
		(layer "In15.Cu")
		(net "FM_ADR_MODE1")
	)
	(segment
		(start 206.624428 -101.727)
		(end 194.74053 -101.727)
		(width 0.127)
		(layer "In15.Cu")
		(net "FM_ADR_MODE1")
	)
	(segment
		(start 319.07988 -110.327948)
		(end 282.98013 -110.327948)
		(width 0.127)
		(layer "In15.Cu")
		(net "FM_ADR_MODE1")
	)
	(segment
		(start 241.576098 -105.336086)
		(end 235.222034 -105.336086)
		(width 0.127)
		(layer "In15.Cu")
		(net "FM_ADR_MODE1")
	)
	(segment
		(start 251.55906 -115.319048)
		(end 241.576098 -105.336086)
		(width 0.127)
		(layer "In15.Cu")
		(net "FM_ADR_MODE1")
	)
	(segment
		(start 194.61353 -101.854)
		(end 194.61353 -102.415848)
		(width 0.127)
		(layer "In15.Cu")
		(net "FM_ADR_MODE1")
	)
	(segment
		(start 186.155584 -106.575352)
		(end 186.555634 -106.175302)
		(width 0.12954)
		(layer "F.Cu")
		(net "FM_ADR_MODE0_R")
	)
	(segment
		(start 321.080892 -22.551898)
		(end 321.135502 -22.497288)
		(width 0.12954)
		(layer "F.Cu")
		(net "FM_ADR_MODE0_R")
	)
	(segment
		(start 321.135502 -22.497288)
		(end 321.863466 -22.497288)
		(width 0.12954)
		(layer "F.Cu")
		(net "FM_ADR_MODE0_R")
	)
	(via
		(at 326.19188 -109.057948)
		(size 0.508)
		(drill 0.254)
		(layers "F.Cu" "B.Cu")
		(net "FM_ADR_MODE0_R")
	)
	(via
		(at 321.080892 -22.551898)
		(size 0.508)
		(drill 0.254)
		(layers "F.Cu" "B.Cu")
		(net "FM_ADR_MODE0_R")
	)
	(via
		(at 186.555634 -106.175302)
		(size 0.4572)
		(drill 0.254)
		(layers "F.Cu" "B.Cu")
		(net "FM_ADR_MODE0_R")
	)
	(segment
		(start 322.0212 -28.743148)
		(end 322.0212 -26.812748)
		(width 0.127)
		(layer "In2.Cu")
		(net "FM_ADR_MODE0_R")
	)
	(segment
		(start 325.67118 -58.367168)
		(end 326.63384 -57.404508)
		(width 0.127)
		(layer "In2.Cu")
		(net "FM_ADR_MODE0_R")
	)
	(segment
		(start 326.63384 -57.404508)
		(end 326.63384 -41.930828)
		(width 0.127)
		(layer "In2.Cu")
		(net "FM_ADR_MODE0_R")
	)
	(segment
		(start 326.63384 -41.930828)
		(end 323.57314 -38.870128)
		(width 0.127)
		(layer "In2.Cu")
		(net "FM_ADR_MODE0_R")
	)
	(segment
		(start 322.98132 -64.183768)
		(end 325.67118 -61.493908)
		(width 0.127)
		(layer "In2.Cu")
		(net "FM_ADR_MODE0_R")
	)
	(segment
		(start 321.8434 -24.196548)
		(end 321.8434 -22.769068)
		(width 0.127)
		(layer "In2.Cu")
		(net "FM_ADR_MODE0_R")
	)
	(segment
		(start 319.5828 -34.432748)
		(end 319.5828 -31.181548)
		(width 0.127)
		(layer "In2.Cu")
		(net "FM_ADR_MODE0_R")
	)
	(segment
		(start 321.135502 -22.497288)
		(end 321.080892 -22.551898)
		(width 0.127)
		(layer "In2.Cu")
		(net "FM_ADR_MODE0_R")
	)
	(segment
		(start 321.8434 -22.769068)
		(end 321.57162 -22.497288)
		(width 0.127)
		(layer "In2.Cu")
		(net "FM_ADR_MODE0_R")
	)
	(segment
		(start 322.67652 -69.583808)
		(end 322.67652 -67.704208)
		(width 0.127)
		(layer "In2.Cu")
		(net "FM_ADR_MODE0_R")
	)
	(segment
		(start 326.19188 -73.099168)
		(end 322.67652 -69.583808)
		(width 0.127)
		(layer "In2.Cu")
		(net "FM_ADR_MODE0_R")
	)
	(segment
		(start 323.57314 -38.423088)
		(end 319.5828 -34.432748)
		(width 0.127)
		(layer "In2.Cu")
		(net "FM_ADR_MODE0_R")
	)
	(segment
		(start 323.57314 -38.870128)
		(end 323.57314 -38.423088)
		(width 0.127)
		(layer "In2.Cu")
		(net "FM_ADR_MODE0_R")
	)
	(segment
		(start 322.67652 -67.704208)
		(end 322.98132 -67.399408)
		(width 0.127)
		(layer "In2.Cu")
		(net "FM_ADR_MODE0_R")
	)
	(segment
		(start 321.57162 -22.497288)
		(end 321.135502 -22.497288)
		(width 0.127)
		(layer "In2.Cu")
		(net "FM_ADR_MODE0_R")
	)
	(segment
		(start 321.2592 -26.050748)
		(end 321.2592 -24.780748)
		(width 0.127)
		(layer "In2.Cu")
		(net "FM_ADR_MODE0_R")
	)
	(segment
		(start 322.98132 -67.399408)
		(end 322.98132 -64.183768)
		(width 0.127)
		(layer "In2.Cu")
		(net "FM_ADR_MODE0_R")
	)
	(segment
		(start 325.67118 -61.493908)
		(end 325.67118 -58.367168)
		(width 0.127)
		(layer "In2.Cu")
		(net "FM_ADR_MODE0_R")
	)
	(segment
		(start 322.0212 -26.812748)
		(end 321.2592 -26.050748)
		(width 0.127)
		(layer "In2.Cu")
		(net "FM_ADR_MODE0_R")
	)
	(segment
		(start 321.2592 -24.780748)
		(end 321.8434 -24.196548)
		(width 0.127)
		(layer "In2.Cu")
		(net "FM_ADR_MODE0_R")
	)
	(segment
		(start 319.5828 -31.181548)
		(end 322.0212 -28.743148)
		(width 0.127)
		(layer "In2.Cu")
		(net "FM_ADR_MODE0_R")
	)
	(segment
		(start 326.19188 -109.057948)
		(end 326.19188 -73.099168)
		(width 0.127)
		(layer "In2.Cu")
		(net "FM_ADR_MODE0_R")
	)
	(segment
		(start 252.370844 -113.363248)
		(end 265.688318 -113.363248)
		(width 0.127)
		(layer "In15.Cu")
		(net "FM_ADR_MODE0_R")
	)
	(segment
		(start 189.49416 -102.982268)
		(end 195.33108 -97.145348)
		(width 0.127)
		(layer "In15.Cu")
		(net "FM_ADR_MODE0_R")
	)
	(segment
		(start 219.601542 -96.281748)
		(end 219.76715 -96.11614)
		(width 0.127)
		(layer "In15.Cu")
		(net "FM_ADR_MODE0_R")
	)
	(segment
		(start 283.16428 -107.533948)
		(end 324.66788 -107.533948)
		(width 0.127)
		(layer "In15.Cu")
		(net "FM_ADR_MODE0_R")
	)
	(segment
		(start 186.555634 -106.175302)
		(end 187.301886 -106.175302)
		(width 0.127)
		(layer "In15.Cu")
		(net "FM_ADR_MODE0_R")
	)
	(segment
		(start 242.387882 -103.380286)
		(end 252.370844 -113.363248)
		(width 0.127)
		(layer "In15.Cu")
		(net "FM_ADR_MODE0_R")
	)
	(segment
		(start 267.021818 -112.029748)
		(end 278.66848 -112.029748)
		(width 0.127)
		(layer "In15.Cu")
		(net "FM_ADR_MODE0_R")
	)
	(segment
		(start 220.946472 -96.11614)
		(end 221.074742 -95.98787)
		(width 0.127)
		(layer "In15.Cu")
		(net "FM_ADR_MODE0_R")
	)
	(segment
		(start 236.033818 -103.380286)
		(end 242.387882 -103.380286)
		(width 0.127)
		(layer "In15.Cu")
		(net "FM_ADR_MODE0_R")
	)
	(segment
		(start 189.49416 -103.983028)
		(end 189.49416 -102.982268)
		(width 0.127)
		(layer "In15.Cu")
		(net "FM_ADR_MODE0_R")
	)
	(segment
		(start 223.11614 -95.98787)
		(end 223.344994 -96.216724)
		(width 0.127)
		(layer "In15.Cu")
		(net "FM_ADR_MODE0_R")
	)
	(segment
		(start 232.1814 -99.527868)
		(end 236.033818 -103.380286)
		(width 0.127)
		(layer "In15.Cu")
		(net "FM_ADR_MODE0_R")
	)
	(segment
		(start 225.38436 -99.527868)
		(end 232.1814 -99.527868)
		(width 0.127)
		(layer "In15.Cu")
		(net "FM_ADR_MODE0_R")
	)
	(segment
		(start 223.344994 -96.216724)
		(end 223.344994 -97.488502)
		(width 0.127)
		(layer "In15.Cu")
		(net "FM_ADR_MODE0_R")
	)
	(segment
		(start 219.76715 -96.11614)
		(end 220.946472 -96.11614)
		(width 0.127)
		(layer "In15.Cu")
		(net "FM_ADR_MODE0_R")
	)
	(segment
		(start 223.344994 -97.488502)
		(end 225.38436 -99.527868)
		(width 0.127)
		(layer "In15.Cu")
		(net "FM_ADR_MODE0_R")
	)
	(segment
		(start 278.66848 -112.029748)
		(end 283.16428 -107.533948)
		(width 0.127)
		(layer "In15.Cu")
		(net "FM_ADR_MODE0_R")
	)
	(segment
		(start 187.301886 -106.175302)
		(end 189.49416 -103.983028)
		(width 0.127)
		(layer "In15.Cu")
		(net "FM_ADR_MODE0_R")
	)
	(segment
		(start 209.473292 -96.281748)
		(end 219.601542 -96.281748)
		(width 0.127)
		(layer "In15.Cu")
		(net "FM_ADR_MODE0_R")
	)
	(segment
		(start 208.609692 -97.145348)
		(end 209.473292 -96.281748)
		(width 0.127)
		(layer "In15.Cu")
		(net "FM_ADR_MODE0_R")
	)
	(segment
		(start 221.074742 -95.98787)
		(end 223.11614 -95.98787)
		(width 0.127)
		(layer "In15.Cu")
		(net "FM_ADR_MODE0_R")
	)
	(segment
		(start 265.688318 -113.363248)
		(end 267.021818 -112.029748)
		(width 0.127)
		(layer "In15.Cu")
		(net "FM_ADR_MODE0_R")
	)
	(segment
		(start 195.33108 -97.145348)
		(end 208.609692 -97.145348)
		(width 0.127)
		(layer "In15.Cu")
		(net "FM_ADR_MODE0_R")
	)
	(segment
		(start 324.66788 -107.533948)
		(end 326.19188 -109.057948)
		(width 0.127)
		(layer "In15.Cu")
		(net "FM_ADR_MODE0_R")
	)
	(segment
		(start 322.663566 -24.579072)
		(end 322.663566 -23.551896)
		(width 0.12954)
		(layer "F.Cu")
		(net "FM_ADR_MODE0")
	)
	(segment
		(start 322.663566 -22.497288)
		(end 322.663566 -23.551896)
		(width 0.12954)
		(layer "F.Cu")
		(net "FM_ADR_MODE0")
	)
	(segment
		(start 331.608176 -41.871646)
		(end 331.067918 -41.871646)
		(width 0.12954)
		(layer "F.Cu")
		(net "FM_ADR_MODE0")
	)
	(segment
		(start 322.663566 -25.656794)
		(end 322.663566 -24.579072)
		(width 0.12954)
		(layer "F.Cu")
		(net "FM_ADR_MODE0")
	)
	(via
		(at 407.4668 -59.599068)
		(size 0.762)
		(drill 0.254)
		(layers "F.Cu" "B.Cu")
		(net "FM_ADR_MODE0")
	)
	(via
		(at 322.663566 -25.656794)
		(size 0.508)
		(drill 0.254)
		(layers "F.Cu" "B.Cu")
		(net "FM_ADR_MODE0")
	)
	(via
		(at 331.067918 -41.871646)
		(size 0.4572)
		(drill 0.2032)
		(layers "F.Cu" "B.Cu")
		(net "FM_ADR_MODE0")
	)
	(segment
		(start 407.12644 -59.939428)
		(end 404.402798 -59.939428)
		(width 0.12954)
		(layer "B.Cu")
		(net "FM_ADR_MODE0")
	)
	(segment
		(start 407.4668 -59.599068)
		(end 407.12644 -59.939428)
		(width 0.12954)
		(layer "B.Cu")
		(net "FM_ADR_MODE0")
	)
	(segment
		(start 342.48344 -46.647608)
		(end 342.48344 -46.439328)
		(width 0.127)
		(layer "In4.Cu")
		(net "FM_ADR_MODE0")
	)
	(segment
		(start 338.93506 -41.466008)
		(end 338.58454 -41.816528)
		(width 0.127)
		(layer "In4.Cu")
		(net "FM_ADR_MODE0")
	)
	(segment
		(start 342.16086 -46.116748)
		(end 341.77224 -46.116748)
		(width 0.127)
		(layer "In4.Cu")
		(net "FM_ADR_MODE0")
	)
	(segment
		(start 343.3191 -47.991268)
		(end 342.88984 -47.562008)
		(width 0.127)
		(layer "In4.Cu")
		(net "FM_ADR_MODE0")
	)
	(segment
		(start 341.6935 -45.128688)
		(end 342.0872 -45.128688)
		(width 0.127)
		(layer "In4.Cu")
		(net "FM_ADR_MODE0")
	)
	(segment
		(start 382.02108 -65.169796)
		(end 380.790196 -63.938912)
		(width 0.127)
		(layer "In4.Cu")
		(net "FM_ADR_MODE0")
	)
	(segment
		(start 335.30032 -41.874948)
		(end 334.9117 -41.874948)
		(width 0.127)
		(layer "In4.Cu")
		(net "FM_ADR_MODE0")
	)
	(segment
		(start 342.88984 -47.562008)
		(end 342.6333 -47.562008)
		(width 0.127)
		(layer "In4.Cu")
		(net "FM_ADR_MODE0")
	)
	(segment
		(start 342.27516 -46.855888)
		(end 342.48344 -46.647608)
		(width 0.127)
		(layer "In4.Cu")
		(net "FM_ADR_MODE0")
	)
	(segment
		(start 342.36914 -44.846748)
		(end 342.36914 -44.445428)
		(width 0.127)
		(layer "In4.Cu")
		(net "FM_ADR_MODE0")
	)
	(segment
		(start 348.00794 -49.022508)
		(end 345.1987 -49.022508)
		(width 0.127)
		(layer "In4.Cu")
		(net "FM_ADR_MODE0")
	)
	(segment
		(start 407.4668 -59.599068)
		(end 401.07108 -59.599068)
		(width 0.127)
		(layer "In4.Cu")
		(net "FM_ADR_MODE0")
	)
	(segment
		(start 342.36914 -44.445428)
		(end 342.15578 -44.232068)
		(width 0.127)
		(layer "In4.Cu")
		(net "FM_ADR_MODE0")
	)
	(segment
		(start 342.48344 -46.439328)
		(end 342.16086 -46.116748)
		(width 0.127)
		(layer "In4.Cu")
		(net "FM_ADR_MODE0")
	)
	(segment
		(start 335.8261 -41.349168)
		(end 335.30032 -41.874948)
		(width 0.127)
		(layer "In4.Cu")
		(net "FM_ADR_MODE0")
	)
	(segment
		(start 334.43418 -41.397428)
		(end 334.18018 -41.397428)
		(width 0.127)
		(layer "In4.Cu")
		(net "FM_ADR_MODE0")
	)
	(segment
		(start 333.74584 -41.831768)
		(end 333.29626 -41.831768)
		(width 0.127)
		(layer "In4.Cu")
		(net "FM_ADR_MODE0")
	)
	(segment
		(start 345.1987 -49.022508)
		(end 345.0717 -48.895508)
		(width 0.127)
		(layer "In4.Cu")
		(net "FM_ADR_MODE0")
	)
	(segment
		(start 340.89086 -41.874948)
		(end 340.48192 -41.466008)
		(width 0.127)
		(layer "In4.Cu")
		(net "FM_ADR_MODE0")
	)
	(segment
		(start 342.0872 -45.128688)
		(end 342.36914 -44.846748)
		(width 0.127)
		(layer "In4.Cu")
		(net "FM_ADR_MODE0")
	)
	(segment
		(start 342.15578 -44.232068)
		(end 341.72144 -44.232068)
		(width 0.127)
		(layer "In4.Cu")
		(net "FM_ADR_MODE0")
	)
	(segment
		(start 344.29192 -48.517048)
		(end 343.76614 -47.991268)
		(width 0.127)
		(layer "In4.Cu")
		(net "FM_ADR_MODE0")
	)
	(segment
		(start 366.14608 -58.427112)
		(end 364.900972 -59.67222)
		(width 0.127)
		(layer "In4.Cu")
		(net "FM_ADR_MODE0")
	)
	(segment
		(start 342.27516 -47.203868)
		(end 342.27516 -46.855888)
		(width 0.127)
		(layer "In4.Cu")
		(net "FM_ADR_MODE0")
	)
	(segment
		(start 358.657652 -59.67222)
		(end 348.00794 -49.022508)
		(width 0.127)
		(layer "In4.Cu")
		(net "FM_ADR_MODE0")
	)
	(segment
		(start 370.566188 -58.427112)
		(end 366.14608 -58.427112)
		(width 0.127)
		(layer "In4.Cu")
		(net "FM_ADR_MODE0")
	)
	(segment
		(start 343.76614 -47.991268)
		(end 343.3191 -47.991268)
		(width 0.127)
		(layer "In4.Cu")
		(net "FM_ADR_MODE0")
	)
	(segment
		(start 341.50808 -44.018708)
		(end 341.50808 -41.974008)
		(width 0.127)
		(layer "In4.Cu")
		(net "FM_ADR_MODE0")
	)
	(segment
		(start 340.48192 -41.466008)
		(end 338.93506 -41.466008)
		(width 0.127)
		(layer "In4.Cu")
		(net "FM_ADR_MODE0")
	)
	(segment
		(start 333.29626 -41.831768)
		(end 332.89748 -41.432988)
		(width 0.127)
		(layer "In4.Cu")
		(net "FM_ADR_MODE0")
	)
	(segment
		(start 380.790196 -59.93257)
		(end 379.993652 -59.136026)
		(width 0.127)
		(layer "In4.Cu")
		(net "FM_ADR_MODE0")
	)
	(segment
		(start 401.07108 -59.599068)
		(end 395.500352 -65.169796)
		(width 0.127)
		(layer "In4.Cu")
		(net "FM_ADR_MODE0")
	)
	(segment
		(start 380.790196 -63.938912)
		(end 380.790196 -59.93257)
		(width 0.127)
		(layer "In4.Cu")
		(net "FM_ADR_MODE0")
	)
	(segment
		(start 332.89748 -41.432988)
		(end 332.5368 -41.432988)
		(width 0.127)
		(layer "In4.Cu")
		(net "FM_ADR_MODE0")
	)
	(segment
		(start 332.11008 -41.859708)
		(end 331.079856 -41.859708)
		(width 0.127)
		(layer "In4.Cu")
		(net "FM_ADR_MODE0")
	)
	(segment
		(start 379.993652 -59.136026)
		(end 371.275102 -59.136026)
		(width 0.127)
		(layer "In4.Cu")
		(net "FM_ADR_MODE0")
	)
	(segment
		(start 338.58454 -41.816528)
		(end 338.18322 -41.816528)
		(width 0.127)
		(layer "In4.Cu")
		(net "FM_ADR_MODE0")
	)
	(segment
		(start 334.9117 -41.874948)
		(end 334.43418 -41.397428)
		(width 0.127)
		(layer "In4.Cu")
		(net "FM_ADR_MODE0")
	)
	(segment
		(start 341.72144 -44.232068)
		(end 341.50808 -44.018708)
		(width 0.127)
		(layer "In4.Cu")
		(net "FM_ADR_MODE0")
	)
	(segment
		(start 395.500352 -65.169796)
		(end 382.02108 -65.169796)
		(width 0.127)
		(layer "In4.Cu")
		(net "FM_ADR_MODE0")
	)
	(segment
		(start 341.50808 -45.852588)
		(end 341.50808 -45.314108)
		(width 0.127)
		(layer "In4.Cu")
		(net "FM_ADR_MODE0")
	)
	(segment
		(start 371.275102 -59.136026)
		(end 370.566188 -58.427112)
		(width 0.127)
		(layer "In4.Cu")
		(net "FM_ADR_MODE0")
	)
	(segment
		(start 364.900972 -59.67222)
		(end 358.657652 -59.67222)
		(width 0.127)
		(layer "In4.Cu")
		(net "FM_ADR_MODE0")
	)
	(segment
		(start 337.71586 -41.349168)
		(end 335.8261 -41.349168)
		(width 0.127)
		(layer "In4.Cu")
		(net "FM_ADR_MODE0")
	)
	(segment
		(start 331.079856 -41.859708)
		(end 331.067918 -41.871646)
		(width 0.127)
		(layer "In4.Cu")
		(net "FM_ADR_MODE0")
	)
	(segment
		(start 341.50808 -41.974008)
		(end 341.40902 -41.874948)
		(width 0.127)
		(layer "In4.Cu")
		(net "FM_ADR_MODE0")
	)
	(segment
		(start 341.77224 -46.116748)
		(end 341.50808 -45.852588)
		(width 0.127)
		(layer "In4.Cu")
		(net "FM_ADR_MODE0")
	)
	(segment
		(start 342.6333 -47.562008)
		(end 342.27516 -47.203868)
		(width 0.127)
		(layer "In4.Cu")
		(net "FM_ADR_MODE0")
	)
	(segment
		(start 334.18018 -41.397428)
		(end 333.74584 -41.831768)
		(width 0.127)
		(layer "In4.Cu")
		(net "FM_ADR_MODE0")
	)
	(segment
		(start 332.5368 -41.432988)
		(end 332.11008 -41.859708)
		(width 0.127)
		(layer "In4.Cu")
		(net "FM_ADR_MODE0")
	)
	(segment
		(start 345.0717 -48.895508)
		(end 345.0717 -48.887888)
		(width 0.127)
		(layer "In4.Cu")
		(net "FM_ADR_MODE0")
	)
	(segment
		(start 345.0717 -48.887888)
		(end 344.70086 -48.517048)
		(width 0.127)
		(layer "In4.Cu")
		(net "FM_ADR_MODE0")
	)
	(segment
		(start 338.18322 -41.816528)
		(end 337.71586 -41.349168)
		(width 0.127)
		(layer "In4.Cu")
		(net "FM_ADR_MODE0")
	)
	(segment
		(start 341.50808 -45.314108)
		(end 341.6935 -45.128688)
		(width 0.127)
		(layer "In4.Cu")
		(net "FM_ADR_MODE0")
	)
	(segment
		(start 341.40902 -41.874948)
		(end 340.89086 -41.874948)
		(width 0.127)
		(layer "In4.Cu")
		(net "FM_ADR_MODE0")
	)
	(segment
		(start 344.70086 -48.517048)
		(end 344.29192 -48.517048)
		(width 0.127)
		(layer "In4.Cu")
		(net "FM_ADR_MODE0")
	)
	(segment
		(start 330.93152 -40.437308)
		(end 331.2795 -40.437308)
		(width 0.127)
		(layer "In11.Cu")
		(net "FM_ADR_MODE0")
	)
	(segment
		(start 331.56398 -39.301928)
		(end 330.68514 -38.423088)
		(width 0.127)
		(layer "In11.Cu")
		(net "FM_ADR_MODE0")
	)
	(segment
		(start 330.61148 -41.118028)
		(end 330.61148 -40.757348)
		(width 0.127)
		(layer "In11.Cu")
		(net "FM_ADR_MODE0")
	)
	(segment
		(start 328.76744 -31.801308)
		(end 322.663566 -25.697434)
		(width 0.127)
		(layer "In11.Cu")
		(net "FM_ADR_MODE0")
	)
	(segment
		(start 331.2795 -40.437308)
		(end 331.56398 -40.152828)
		(width 0.127)
		(layer "In11.Cu")
		(net "FM_ADR_MODE0")
	)
	(segment
		(start 329.90536 -36.010088)
		(end 329.90536 -35.232848)
		(width 0.127)
		(layer "In11.Cu")
		(net "FM_ADR_MODE0")
	)
	(segment
		(start 331.067918 -41.871646)
		(end 331.067918 -41.574466)
		(width 0.127)
		(layer "In11.Cu")
		(net "FM_ADR_MODE0")
	)
	(segment
		(start 322.663566 -25.697434)
		(end 322.663566 -25.656794)
		(width 0.127)
		(layer "In11.Cu")
		(net "FM_ADR_MODE0")
	)
	(segment
		(start 330.61148 -40.757348)
		(end 330.93152 -40.437308)
		(width 0.127)
		(layer "In11.Cu")
		(net "FM_ADR_MODE0")
	)
	(segment
		(start 330.68514 -36.789868)
		(end 329.90536 -36.010088)
		(width 0.127)
		(layer "In11.Cu")
		(net "FM_ADR_MODE0")
	)
	(segment
		(start 328.76744 -34.094928)
		(end 328.76744 -31.801308)
		(width 0.127)
		(layer "In11.Cu")
		(net "FM_ADR_MODE0")
	)
	(segment
		(start 331.56398 -40.152828)
		(end 331.56398 -39.301928)
		(width 0.127)
		(layer "In11.Cu")
		(net "FM_ADR_MODE0")
	)
	(segment
		(start 330.68514 -38.423088)
		(end 330.68514 -36.789868)
		(width 0.127)
		(layer "In11.Cu")
		(net "FM_ADR_MODE0")
	)
	(segment
		(start 329.90536 -35.232848)
		(end 328.76744 -34.094928)
		(width 0.127)
		(layer "In11.Cu")
		(net "FM_ADR_MODE0")
	)
	(segment
		(start 331.067918 -41.574466)
		(end 330.61148 -41.118028)
		(width 0.127)
		(layer "In11.Cu")
		(net "FM_ADR_MODE0")
	)
	(segment
		(start 324.864222 -49.088548)
		(end 325.16699 -49.088548)
		(width 0.0889)
		(layer "F.Cu")
		(net "FM_ADR_COMPLETE")
	)
	(segment
		(start 325.16699 -49.088548)
		(end 325.305166 -48.950372)
		(width 0.0889)
		(layer "F.Cu")
		(net "FM_ADR_COMPLETE")
	)
	(segment
		(start 304.435002 -54.012592)
		(end 305.044602 -54.012592)
		(width 0.12954)
		(layer "F.Cu")
		(net "FM_ADR_COMPLETE")
	)
	(segment
		(start 182.955692 -108.975398)
		(end 183.355742 -108.575348)
		(width 0.12954)
		(layer "F.Cu")
		(net "FM_ADR_COMPLETE")
	)
	(segment
		(start 325.305166 -48.950372)
		(end 326.584818 -48.950372)
		(width 0.0889)
		(layer "F.Cu")
		(net "FM_ADR_COMPLETE")
	)
	(via
		(at 305.044602 -54.012592)
		(size 0.508)
		(drill 0.254)
		(layers "F.Cu" "B.Cu")
		(net "FM_ADR_COMPLETE")
	)
	(via
		(at 325.18858 -110.327948)
		(size 0.508)
		(drill 0.254)
		(layers "F.Cu" "B.Cu")
		(net "FM_ADR_COMPLETE")
	)
	(via
		(at 324.864222 -49.088548)
		(size 0.508)
		(drill 0.254)
		(layers "F.Cu" "B.Cu")
		(net "FM_ADR_COMPLETE")
	)
	(via
		(at 183.355742 -108.575348)
		(size 0.4572)
		(drill 0.254)
		(layers "F.Cu" "B.Cu")
		(net "FM_ADR_COMPLETE")
	)
	(segment
		(start 324.8279 -54.600348)
		(end 323.506592 -55.921656)
		(width 0.127)
		(layer "In2.Cu")
		(net "FM_ADR_COMPLETE")
	)
	(segment
		(start 324.11924 -50.696368)
		(end 324.11924 -51.679348)
		(width 0.127)
		(layer "In2.Cu")
		(net "FM_ADR_COMPLETE")
	)
	(segment
		(start 323.506592 -61.537088)
		(end 322.04152 -63.00216)
		(width 0.127)
		(layer "In2.Cu")
		(net "FM_ADR_COMPLETE")
	)
	(segment
		(start 325.18858 -73.396348)
		(end 325.18858 -110.327948)
		(width 0.127)
		(layer "In2.Cu")
		(net "FM_ADR_COMPLETE")
	)
	(segment
		(start 322.04152 -66.685668)
		(end 321.72402 -67.003168)
		(width 0.127)
		(layer "In2.Cu")
		(net "FM_ADR_COMPLETE")
	)
	(segment
		(start 321.72402 -69.931788)
		(end 325.18858 -73.396348)
		(width 0.127)
		(layer "In2.Cu")
		(net "FM_ADR_COMPLETE")
	)
	(segment
		(start 324.864222 -49.951386)
		(end 324.11924 -50.696368)
		(width 0.127)
		(layer "In2.Cu")
		(net "FM_ADR_COMPLETE")
	)
	(segment
		(start 324.11924 -51.679348)
		(end 324.8279 -52.388008)
		(width 0.127)
		(layer "In2.Cu")
		(net "FM_ADR_COMPLETE")
	)
	(segment
		(start 321.72402 -67.003168)
		(end 321.72402 -69.931788)
		(width 0.127)
		(layer "In2.Cu")
		(net "FM_ADR_COMPLETE")
	)
	(segment
		(start 324.8279 -52.388008)
		(end 324.8279 -54.600348)
		(width 0.127)
		(layer "In2.Cu")
		(net "FM_ADR_COMPLETE")
	)
	(segment
		(start 322.04152 -63.00216)
		(end 322.04152 -66.685668)
		(width 0.127)
		(layer "In2.Cu")
		(net "FM_ADR_COMPLETE")
	)
	(segment
		(start 324.864222 -49.088548)
		(end 324.864222 -49.951386)
		(width 0.127)
		(layer "In2.Cu")
		(net "FM_ADR_COMPLETE")
	)
	(segment
		(start 323.506592 -55.921656)
		(end 323.506592 -61.537088)
		(width 0.127)
		(layer "In2.Cu")
		(net "FM_ADR_COMPLETE")
	)
	(segment
		(start 187.646564 -108.176568)
		(end 183.754522 -108.176568)
		(width 0.127)
		(layer "In15.Cu")
		(net "FM_ADR_COMPLETE")
	)
	(segment
		(start 343.45372 -37.419788)
		(end 338.91474 -37.419788)
		(width 0.127)
		(layer "In15.Cu")
		(net "FM_ADR_COMPLETE")
	)
	(segment
		(start 208.0006 -99.875848)
		(end 207.3529 -100.523548)
		(width 0.127)
		(layer "In15.Cu")
		(net "FM_ADR_COMPLETE")
	)
	(segment
		(start 324.68058 -109.819948)
		(end 282.776676 -109.819948)
		(width 0.127)
		(layer "In15.Cu")
		(net "FM_ADR_COMPLETE")
	)
	(segment
		(start 345.19108 -36.523168)
		(end 344.35034 -36.523168)
		(width 0.127)
		(layer "In15.Cu")
		(net "FM_ADR_COMPLETE")
	)
	(segment
		(start 429.745394 -28.402788)
		(end 424.38828 -28.402788)
		(width 0.127)
		(layer "In15.Cu")
		(net "FM_ADR_COMPLETE")
	)
	(segment
		(start 429.99406 -35.692588)
		(end 428.1424 -35.692588)
		(width 0.127)
		(layer "In15.Cu")
		(net "FM_ADR_COMPLETE")
	)
	(segment
		(start 430.6062 -36.304728)
		(end 429.99406 -35.692588)
		(width 0.127)
		(layer "In15.Cu")
		(net "FM_ADR_COMPLETE")
	)
	(segment
		(start 428.4472 -33.188148)
		(end 429.68926 -33.188148)
		(width 0.127)
		(layer "In15.Cu")
		(net "FM_ADR_COMPLETE")
	)
	(segment
		(start 372.04142 -48.687228)
		(end 355.563932 -48.687228)
		(width 0.127)
		(layer "In15.Cu")
		(net "FM_ADR_COMPLETE")
	)
	(segment
		(start 427.81728 -33.818068)
		(end 428.4472 -33.188148)
		(width 0.127)
		(layer "In15.Cu")
		(net "FM_ADR_COMPLETE")
	)
	(segment
		(start 401.33016 -37.023548)
		(end 393.2047 -45.149008)
		(width 0.127)
		(layer "In15.Cu")
		(net "FM_ADR_COMPLETE")
	)
	(segment
		(start 355.563932 -48.687228)
		(end 348.64802 -41.771316)
		(width 0.127)
		(layer "In15.Cu")
		(net "FM_ADR_COMPLETE")
	)
	(segment
		(start 375.57964 -45.149008)
		(end 372.04142 -48.687228)
		(width 0.127)
		(layer "In15.Cu")
		(net "FM_ADR_COMPLETE")
	)
	(segment
		(start 324.14464 -42.370248)
		(end 324.14464 -47.027338)
		(width 0.127)
		(layer "In15.Cu")
		(net "FM_ADR_COMPLETE")
	)
	(segment
		(start 323.581522 -47.805848)
		(end 324.864222 -49.088548)
		(width 0.127)
		(layer "In15.Cu")
		(net "FM_ADR_COMPLETE")
	)
	(segment
		(start 324.864222 -47.74692)
		(end 324.864222 -49.088548)
		(width 0.127)
		(layer "In15.Cu")
		(net "FM_ADR_COMPLETE")
	)
	(segment
		(start 319.69456 -49.065688)
		(end 320.9544 -47.805848)
		(width 0.127)
		(layer "In15.Cu")
		(net "FM_ADR_COMPLETE")
	)
	(segment
		(start 308.252876 -54.012592)
		(end 310.17972 -52.085748)
		(width 0.127)
		(layer "In15.Cu")
		(net "FM_ADR_COMPLETE")
	)
	(segment
		(start 183.754522 -108.176568)
		(end 183.355742 -108.575348)
		(width 0.127)
		(layer "In15.Cu")
		(net "FM_ADR_COMPLETE")
	)
	(segment
		(start 415.76752 -37.023548)
		(end 401.33016 -37.023548)
		(width 0.127)
		(layer "In15.Cu")
		(net "FM_ADR_COMPLETE")
	)
	(segment
		(start 282.776676 -109.819948)
		(end 279.373076 -113.223548)
		(width 0.127)
		(layer "In15.Cu")
		(net "FM_ADR_COMPLETE")
	)
	(segment
		(start 219.393008 -99.7204)
		(end 218.851988 -100.26142)
		(width 0.127)
		(layer "In15.Cu")
		(net "FM_ADR_COMPLETE")
	)
	(segment
		(start 241.713258 -105.005886)
		(end 235.359194 -105.005886)
		(width 0.127)
		(layer "In15.Cu")
		(net "FM_ADR_COMPLETE")
	)
	(segment
		(start 429.170084 -39.539926)
		(end 429.16983 -39.539672)
		(width 0.127)
		(layer "In15.Cu")
		(net "FM_ADR_COMPLETE")
	)
	(segment
		(start 338.17052 -36.675568)
		(end 332.14056 -36.675568)
		(width 0.127)
		(layer "In15.Cu")
		(net "FM_ADR_COMPLETE")
	)
	(segment
		(start 424.38828 -28.402788)
		(end 415.76752 -37.023548)
		(width 0.127)
		(layer "In15.Cu")
		(net "FM_ADR_COMPLETE")
	)
	(segment
		(start 329.52817 -38.437058)
		(end 328.07783 -38.437058)
		(width 0.127)
		(layer "In15.Cu")
		(net "FM_ADR_COMPLETE")
	)
	(segment
		(start 305.044602 -54.012592)
		(end 308.252876 -54.012592)
		(width 0.127)
		(layer "In15.Cu")
		(net "FM_ADR_COMPLETE")
	)
	(segment
		(start 279.373076 -113.223548)
		(end 268.281404 -113.223548)
		(width 0.127)
		(layer "In15.Cu")
		(net "FM_ADR_COMPLETE")
	)
	(segment
		(start 338.91474 -37.419788)
		(end 338.17052 -36.675568)
		(width 0.127)
		(layer "In15.Cu")
		(net "FM_ADR_COMPLETE")
	)
	(segment
		(start 320.9544 -47.805848)
		(end 323.581522 -47.805848)
		(width 0.127)
		(layer "In15.Cu")
		(net "FM_ADR_COMPLETE")
	)
	(segment
		(start 312.22188 -49.065688)
		(end 319.69456 -49.065688)
		(width 0.127)
		(layer "In15.Cu")
		(net "FM_ADR_COMPLETE")
	)
	(segment
		(start 191.02832 -103.599488)
		(end 191.02832 -104.794812)
		(width 0.127)
		(layer "In15.Cu")
		(net "FM_ADR_COMPLETE")
	)
	(segment
		(start 328.07783 -38.437058)
		(end 324.14464 -42.370248)
		(width 0.127)
		(layer "In15.Cu")
		(net "FM_ADR_COMPLETE")
	)
	(segment
		(start 194.10426 -100.523548)
		(end 191.02832 -103.599488)
		(width 0.127)
		(layer "In15.Cu")
		(net "FM_ADR_COMPLETE")
	)
	(segment
		(start 345.61272 -37.229288)
		(end 345.61272 -36.944808)
		(width 0.127)
		(layer "In15.Cu")
		(net "FM_ADR_COMPLETE")
	)
	(segment
		(start 210.46694 -99.875848)
		(end 208.0006 -99.875848)
		(width 0.127)
		(layer "In15.Cu")
		(net "FM_ADR_COMPLETE")
	)
	(segment
		(start 251.69622 -114.988848)
		(end 241.713258 -105.005886)
		(width 0.127)
		(layer "In15.Cu")
		(net "FM_ADR_COMPLETE")
	)
	(segment
		(start 332.14056 -36.675568)
		(end 331.40523 -37.410898)
		(width 0.127)
		(layer "In15.Cu")
		(net "FM_ADR_COMPLETE")
	)
	(segment
		(start 330.55433 -37.410898)
		(end 329.52817 -38.437058)
		(width 0.127)
		(layer "In15.Cu")
		(net "FM_ADR_COMPLETE")
	)
	(segment
		(start 331.40523 -37.410898)
		(end 330.55433 -37.410898)
		(width 0.127)
		(layer "In15.Cu")
		(net "FM_ADR_COMPLETE")
	)
	(segment
		(start 427.81728 -35.367468)
		(end 427.81728 -33.818068)
		(width 0.127)
		(layer "In15.Cu")
		(net "FM_ADR_COMPLETE")
	)
	(segment
		(start 428.1424 -35.692588)
		(end 427.81728 -35.367468)
		(width 0.127)
		(layer "In15.Cu")
		(net "FM_ADR_COMPLETE")
	)
	(segment
		(start 429.68926 -33.188148)
		(end 430.38776 -32.489648)
		(width 0.127)
		(layer "In15.Cu")
		(net "FM_ADR_COMPLETE")
	)
	(segment
		(start 324.14464 -47.027338)
		(end 324.864222 -47.74692)
		(width 0.127)
		(layer "In15.Cu")
		(net "FM_ADR_COMPLETE")
	)
	(segment
		(start 430.38776 -29.045154)
		(end 429.745394 -28.402788)
		(width 0.127)
		(layer "In15.Cu")
		(net "FM_ADR_COMPLETE")
	)
	(segment
		(start 222.78594 -101.153468)
		(end 221.352872 -99.7204)
		(width 0.127)
		(layer "In15.Cu")
		(net "FM_ADR_COMPLETE")
	)
	(segment
		(start 393.2047 -45.149008)
		(end 375.57964 -45.149008)
		(width 0.127)
		(layer "In15.Cu")
		(net "FM_ADR_COMPLETE")
	)
	(segment
		(start 207.3529 -100.523548)
		(end 194.10426 -100.523548)
		(width 0.127)
		(layer "In15.Cu")
		(net "FM_ADR_COMPLETE")
	)
	(segment
		(start 268.281404 -113.223548)
		(end 266.516104 -114.988848)
		(width 0.127)
		(layer "In15.Cu")
		(net "FM_ADR_COMPLETE")
	)
	(segment
		(start 345.61272 -36.944808)
		(end 345.19108 -36.523168)
		(width 0.127)
		(layer "In15.Cu")
		(net "FM_ADR_COMPLETE")
	)
	(segment
		(start 235.359194 -105.005886)
		(end 231.506776 -101.153468)
		(width 0.127)
		(layer "In15.Cu")
		(net "FM_ADR_COMPLETE")
	)
	(segment
		(start 429.16983 -39.534338)
		(end 430.6062 -38.097968)
		(width 0.127)
		(layer "In15.Cu")
		(net "FM_ADR_COMPLETE")
	)
	(segment
		(start 218.851988 -100.26142)
		(end 210.852512 -100.26142)
		(width 0.127)
		(layer "In15.Cu")
		(net "FM_ADR_COMPLETE")
	)
	(segment
		(start 344.35034 -36.523168)
		(end 343.45372 -37.419788)
		(width 0.127)
		(layer "In15.Cu")
		(net "FM_ADR_COMPLETE")
	)
	(segment
		(start 348.64802 -38.870128)
		(end 348.00032 -38.222428)
		(width 0.127)
		(layer "In15.Cu")
		(net "FM_ADR_COMPLETE")
	)
	(segment
		(start 191.02832 -104.794812)
		(end 187.646564 -108.176568)
		(width 0.127)
		(layer "In15.Cu")
		(net "FM_ADR_COMPLETE")
	)
	(segment
		(start 348.64802 -41.771316)
		(end 348.64802 -38.870128)
		(width 0.127)
		(layer "In15.Cu")
		(net "FM_ADR_COMPLETE")
	)
	(segment
		(start 210.852512 -100.26142)
		(end 210.46694 -99.875848)
		(width 0.127)
		(layer "In15.Cu")
		(net "FM_ADR_COMPLETE")
	)
	(segment
		(start 346.60586 -38.222428)
		(end 345.61272 -37.229288)
		(width 0.127)
		(layer "In15.Cu")
		(net "FM_ADR_COMPLETE")
	)
	(segment
		(start 430.6062 -38.097968)
		(end 430.6062 -36.304728)
		(width 0.127)
		(layer "In15.Cu")
		(net "FM_ADR_COMPLETE")
	)
	(segment
		(start 231.506776 -101.153468)
		(end 222.78594 -101.153468)
		(width 0.127)
		(layer "In15.Cu")
		(net "FM_ADR_COMPLETE")
	)
	(segment
		(start 429.16983 -39.539672)
		(end 429.16983 -39.534338)
		(width 0.127)
		(layer "In15.Cu")
		(net "FM_ADR_COMPLETE")
	)
	(segment
		(start 221.352872 -99.7204)
		(end 219.393008 -99.7204)
		(width 0.127)
		(layer "In15.Cu")
		(net "FM_ADR_COMPLETE")
	)
	(segment
		(start 348.00032 -38.222428)
		(end 346.60586 -38.222428)
		(width 0.127)
		(layer "In15.Cu")
		(net "FM_ADR_COMPLETE")
	)
	(segment
		(start 310.17972 -51.107848)
		(end 312.22188 -49.065688)
		(width 0.127)
		(layer "In15.Cu")
		(net "FM_ADR_COMPLETE")
	)
	(segment
		(start 266.516104 -114.988848)
		(end 251.69622 -114.988848)
		(width 0.127)
		(layer "In15.Cu")
		(net "FM_ADR_COMPLETE")
	)
	(segment
		(start 310.17972 -52.085748)
		(end 310.17972 -51.107848)
		(width 0.127)
		(layer "In15.Cu")
		(net "FM_ADR_COMPLETE")
	)
	(segment
		(start 430.38776 -32.489648)
		(end 430.38776 -29.045154)
		(width 0.127)
		(layer "In15.Cu")
		(net "FM_ADR_COMPLETE")
	)
	(segment
		(start 325.18858 -110.327948)
		(end 324.68058 -109.819948)
		(width 0.127)
		(layer "In15.Cu")
		(net "FM_ADR_COMPLETE")
	)
	(segment
		(start 186.155584 -105.775506)
		(end 186.556142 -105.374948)
		(width 0.12954)
		(layer "F.Cu")
		(net "FM_ADR_ACK_R")
	)
	(segment
		(start 186.556142 -105.374948)
		(end 189.43828 -105.374948)
		(width 0.12954)
		(layer "F.Cu")
		(net "FM_ADR_ACK_R")
	)
	(segment
		(start 190.50508 -102.235508)
		(end 192.86474 -99.875848)
		(width 0.12954)
		(layer "F.Cu")
		(net "FM_ADR_ACK_R")
	)
	(segment
		(start 189.43828 -105.374948)
		(end 190.50508 -104.308148)
		(width 0.12954)
		(layer "F.Cu")
		(net "FM_ADR_ACK_R")
	)
	(segment
		(start 192.86474 -99.875848)
		(end 193.20383 -99.875848)
		(width 0.12954)
		(layer "F.Cu")
		(net "FM_ADR_ACK_R")
	)
	(segment
		(start 190.50508 -104.308148)
		(end 190.50508 -102.235508)
		(width 0.12954)
		(layer "F.Cu")
		(net "FM_ADR_ACK_R")
	)
	(via
		(at 190.50508 -104.308148)
		(size 0.762)
		(drill 0.381)
		(layers "F.Cu" "B.Cu")
		(net "FM_ADR_ACK_R")
	)
	(segment
		(start 313.13882 -48.463708)
		(end 313.72556 -49.050448)
		(width 0.12954)
		(layer "F.Cu")
		(net "FM_ADR_ACK")
	)
	(segment
		(start 319.933574 -49.233582)
		(end 320.19494 -49.494948)
		(width 0.12954)
		(layer "F.Cu")
		(net "FM_ADR_ACK")
	)
	(segment
		(start 320.19494 -49.494948)
		(end 322.52285 -49.494948)
		(width 0.12954)
		(layer "F.Cu")
		(net "FM_ADR_ACK")
	)
	(segment
		(start 197.01383 -99.875848)
		(end 194.61353 -99.875848)
		(width 0.12954)
		(layer "F.Cu")
		(net "FM_ADR_ACK")
	)
	(segment
		(start 310.676036 -48.463708)
		(end 313.13882 -48.463708)
		(width 0.12954)
		(layer "F.Cu")
		(net "FM_ADR_ACK")
	)
	(segment
		(start 327.143364 -48.751998)
		(end 327.148444 -48.749458)
		(width 0.0889)
		(layer "F.Cu")
		(net "FM_ADR_ACK")
	)
	(segment
		(start 326.82942 -48.751998)
		(end 327.143364 -48.751998)
		(width 0.0889)
		(layer "F.Cu")
		(net "FM_ADR_ACK")
	)
	(segment
		(start 194.61353 -99.875848)
		(end 194.00393 -99.875848)
		(width 0.12954)
		(layer "F.Cu")
		(net "FM_ADR_ACK")
	)
	(segment
		(start 327.148444 -48.749458)
		(end 327.306432 -48.61306)
		(width 0.0889)
		(layer "F.Cu")
		(net "FM_ADR_ACK")
	)
	(segment
		(start 322.52285 -49.494948)
		(end 322.59651 -49.421288)
		(width 0.12954)
		(layer "F.Cu")
		(net "FM_ADR_ACK")
	)
	(segment
		(start 316.489842 -49.233582)
		(end 319.933574 -49.233582)
		(width 0.12954)
		(layer "F.Cu")
		(net "FM_ADR_ACK")
	)
	(segment
		(start 327.306432 -48.61306)
		(end 327.469246 -48.450246)
		(width 0.0889)
		(layer "F.Cu")
		(net "FM_ADR_ACK")
	)
	(segment
		(start 313.72556 -49.050448)
		(end 316.306708 -49.050448)
		(width 0.12954)
		(layer "F.Cu")
		(net "FM_ADR_ACK")
	)
	(segment
		(start 323.134482 -49.421288)
		(end 323.853302 -48.702468)
		(width 0.12954)
		(layer "F.Cu")
		(net "FM_ADR_ACK")
	)
	(segment
		(start 326.702674 -48.642778)
		(end 326.82942 -48.751998)
		(width 0.0889)
		(layer "F.Cu")
		(net "FM_ADR_ACK")
	)
	(segment
		(start 323.912992 -48.642778)
		(end 326.702674 -48.642778)
		(width 0.0889)
		(layer "F.Cu")
		(net "FM_ADR_ACK")
	)
	(segment
		(start 323.853302 -48.702468)
		(end 323.912992 -48.642778)
		(width 0.0889)
		(layer "F.Cu")
		(net "FM_ADR_ACK")
	)
	(segment
		(start 327.469246 -48.450246)
		(end 327.829926 -48.450246)
		(width 0.0889)
		(layer "F.Cu")
		(net "FM_ADR_ACK")
	)
	(segment
		(start 316.306708 -49.050448)
		(end 316.489842 -49.233582)
		(width 0.12954)
		(layer "F.Cu")
		(net "FM_ADR_ACK")
	)
	(segment
		(start 322.59651 -49.421288)
		(end 323.134482 -49.421288)
		(width 0.12954)
		(layer "F.Cu")
		(net "FM_ADR_ACK")
	)
	(via
		(at 323.22262 -109.057948)
		(size 0.508)
		(drill 0.254)
		(layers "F.Cu" "B.Cu")
		(net "FM_ADR_ACK")
	)
	(via
		(at 194.61353 -99.875848)
		(size 0.508)
		(drill 0.254)
		(layers "F.Cu" "B.Cu")
		(net "FM_ADR_ACK")
	)
	(via
		(at 310.676036 -48.463708)
		(size 0.508)
		(drill 0.254)
		(layers "F.Cu" "B.Cu")
		(net "FM_ADR_ACK")
	)
	(segment
		(start 311.33542 -52.037488)
		(end 310.676036 -51.378104)
		(width 0.127)
		(layer "In2.Cu")
		(net "FM_ADR_ACK")
	)
	(segment
		(start 313.75477 -58.728102)
		(end 311.33542 -56.308752)
		(width 0.127)
		(layer "In2.Cu")
		(net "FM_ADR_ACK")
	)
	(segment
		(start 315.884052 -73.104248)
		(end 313.18708 -66.593212)
		(width 0.127)
		(layer "In2.Cu")
		(net "FM_ADR_ACK")
	)
	(segment
		(start 323.22262 -80.442816)
		(end 315.884052 -73.104248)
		(width 0.127)
		(layer "In2.Cu")
		(net "FM_ADR_ACK")
	)
	(segment
		(start 311.33542 -56.308752)
		(end 311.33542 -52.037488)
		(width 0.127)
		(layer "In2.Cu")
		(net "FM_ADR_ACK")
	)
	(segment
		(start 313.18708 -64.955928)
		(end 313.75477 -64.388238)
		(width 0.127)
		(layer "In2.Cu")
		(net "FM_ADR_ACK")
	)
	(segment
		(start 313.18708 -66.593212)
		(end 313.18708 -64.955928)
		(width 0.127)
		(layer "In2.Cu")
		(net "FM_ADR_ACK")
	)
	(segment
		(start 313.75477 -64.388238)
		(end 313.75477 -58.728102)
		(width 0.127)
		(layer "In2.Cu")
		(net "FM_ADR_ACK")
	)
	(segment
		(start 323.22262 -109.057948)
		(end 323.22262 -80.442816)
		(width 0.127)
		(layer "In2.Cu")
		(net "FM_ADR_ACK")
	)
	(segment
		(start 310.676036 -51.378104)
		(end 310.676036 -48.463708)
		(width 0.127)
		(layer "In2.Cu")
		(net "FM_ADR_ACK")
	)
	(segment
		(start 231.643682 -100.823268)
		(end 224.777046 -100.823268)
		(width 0.127)
		(layer "In15.Cu")
		(net "FM_ADR_ACK")
	)
	(segment
		(start 208.368392 -99.304348)
		(end 195.18503 -99.304348)
		(width 0.127)
		(layer "In15.Cu")
		(net "FM_ADR_ACK")
	)
	(segment
		(start 217.951304 -97.689924)
		(end 209.982816 -97.689924)
		(width 0.127)
		(layer "In15.Cu")
		(net "FM_ADR_ACK")
	)
	(segment
		(start 195.18503 -99.304348)
		(end 194.61353 -99.875848)
		(width 0.127)
		(layer "In15.Cu")
		(net "FM_ADR_ACK")
	)
	(segment
		(start 235.4961 -104.675686)
		(end 231.643682 -100.823268)
		(width 0.127)
		(layer "In15.Cu")
		(net "FM_ADR_ACK")
	)
	(segment
		(start 279.062434 -112.893348)
		(end 268.144498 -112.893348)
		(width 0.127)
		(layer "In15.Cu")
		(net "FM_ADR_ACK")
	)
	(segment
		(start 323.22262 -109.057948)
		(end 282.897834 -109.057948)
		(width 0.127)
		(layer "In15.Cu")
		(net "FM_ADR_ACK")
	)
	(segment
		(start 218.95054 -98.68916)
		(end 217.951304 -97.689924)
		(width 0.127)
		(layer "In15.Cu")
		(net "FM_ADR_ACK")
	)
	(segment
		(start 282.897834 -109.057948)
		(end 279.062434 -112.893348)
		(width 0.127)
		(layer "In15.Cu")
		(net "FM_ADR_ACK")
	)
	(segment
		(start 268.144498 -112.893348)
		(end 266.379198 -114.658648)
		(width 0.127)
		(layer "In15.Cu")
		(net "FM_ADR_ACK")
	)
	(segment
		(start 251.833126 -114.658648)
		(end 241.850164 -104.675686)
		(width 0.127)
		(layer "In15.Cu")
		(net "FM_ADR_ACK")
	)
	(segment
		(start 266.379198 -114.658648)
		(end 251.833126 -114.658648)
		(width 0.127)
		(layer "In15.Cu")
		(net "FM_ADR_ACK")
	)
	(segment
		(start 209.982816 -97.689924)
		(end 208.368392 -99.304348)
		(width 0.127)
		(layer "In15.Cu")
		(net "FM_ADR_ACK")
	)
	(segment
		(start 224.777046 -100.823268)
		(end 222.642938 -98.68916)
		(width 0.127)
		(layer "In15.Cu")
		(net "FM_ADR_ACK")
	)
	(segment
		(start 222.642938 -98.68916)
		(end 218.95054 -98.68916)
		(width 0.127)
		(layer "In15.Cu")
		(net "FM_ADR_ACK")
	)
	(segment
		(start 241.850164 -104.675686)
		(end 235.4961 -104.675686)
		(width 0.127)
		(layer "In15.Cu")
		(net "FM_ADR_ACK")
	)
	(segment
		(start 461.841596 -97.864422)
		(end 462.725262 -97.864422)
		(width 0.12954)
		(layer "F.Cu")
		(net "FB_BMC_ISOLATE_R1")
	)
	(segment
		(start 462.725262 -97.864422)
		(end 463.065876 -97.523808)
		(width 0.12954)
		(layer "F.Cu")
		(net "FB_BMC_ISOLATE_R1")
	)
	(segment
		(start 460.529686 -97.864422)
		(end 461.841596 -97.864422)
		(width 0.12954)
		(layer "F.Cu")
		(net "FB_BMC_ISOLATE_R1")
	)
	(via
		(at 461.841596 -97.864422)
		(size 0.762)
		(drill 0.381)
		(layers "F.Cu" "B.Cu")
		(net "FB_BMC_ISOLATE_R1")
	)
	(segment
		(start 463.882232 -95.144844)
		(end 463.865976 -95.1611)
		(width 0.12954)
		(layer "F.Cu")
		(net "FB_BMC_ISOLATE")
	)
	(segment
		(start 466.5345 -97.316544)
		(end 466.5345 -96.407732)
		(width 0.12954)
		(layer "F.Cu")
		(net "FB_BMC_ISOLATE")
	)
	(segment
		(start 368.395758 -17.221708)
		(end 367.284 -17.221708)
		(width 0.12954)
		(layer "F.Cu")
		(net "FB_BMC_ISOLATE")
	)
	(segment
		(start 222.353124 -112.940846)
		(end 221.256606 -114.037364)
		(width 0.12954)
		(layer "F.Cu")
		(net "FB_BMC_ISOLATE")
	)
	(segment
		(start 219.30741 -113.526824)
		(end 219.30741 -113.240566)
		(width 0.12954)
		(layer "F.Cu")
		(net "FB_BMC_ISOLATE")
	)
	(segment
		(start 464.951064 -95.144844)
		(end 463.882232 -95.144844)
		(width 0.12954)
		(layer "F.Cu")
		(net "FB_BMC_ISOLATE")
	)
	(segment
		(start 463.865976 -95.1611)
		(end 463.865976 -96.406208)
		(width 0.12954)
		(layer "F.Cu")
		(net "FB_BMC_ISOLATE")
	)
	(segment
		(start 221.256606 -114.037364)
		(end 219.81795 -114.037364)
		(width 0.12954)
		(layer "F.Cu")
		(net "FB_BMC_ISOLATE")
	)
	(segment
		(start 201.407522 -79.411068)
		(end 201.407522 -80.403192)
		(width 0.12954)
		(layer "F.Cu")
		(net "FB_BMC_ISOLATE")
	)
	(segment
		(start 225.010726 -91.685364)
		(end 225.010726 -98.768154)
		(width 0.12954)
		(layer "F.Cu")
		(net "FB_BMC_ISOLATE")
	)
	(segment
		(start 463.865976 -96.406208)
		(end 463.865976 -97.523808)
		(width 0.12954)
		(layer "F.Cu")
		(net "FB_BMC_ISOLATE")
	)
	(segment
		(start 225.010726 -98.768154)
		(end 226.45116 -100.208588)
		(width 0.12954)
		(layer "F.Cu")
		(net "FB_BMC_ISOLATE")
	)
	(segment
		(start 224.489518 -112.940846)
		(end 222.353124 -112.940846)
		(width 0.12954)
		(layer "F.Cu")
		(net "FB_BMC_ISOLATE")
	)
	(segment
		(start 226.45116 -100.208588)
		(end 226.45116 -110.979204)
		(width 0.12954)
		(layer "F.Cu")
		(net "FB_BMC_ISOLATE")
	)
	(segment
		(start 201.407522 -80.403192)
		(end 202.646026 -81.641696)
		(width 0.12954)
		(layer "F.Cu")
		(net "FB_BMC_ISOLATE")
	)
	(segment
		(start 202.646026 -81.641696)
		(end 214.967058 -81.641696)
		(width 0.12954)
		(layer "F.Cu")
		(net "FB_BMC_ISOLATE")
	)
	(segment
		(start 226.45116 -110.979204)
		(end 224.489518 -112.940846)
		(width 0.12954)
		(layer "F.Cu")
		(net "FB_BMC_ISOLATE")
	)
	(segment
		(start 219.81795 -114.037364)
		(end 219.30741 -113.526824)
		(width 0.12954)
		(layer "F.Cu")
		(net "FB_BMC_ISOLATE")
	)
	(segment
		(start 214.967058 -81.641696)
		(end 225.010726 -91.685364)
		(width 0.12954)
		(layer "F.Cu")
		(net "FB_BMC_ISOLATE")
	)
	(segment
		(start 466.418676 -97.432368)
		(end 466.5345 -97.316544)
		(width 0.12954)
		(layer "F.Cu")
		(net "FB_BMC_ISOLATE")
	)
	(segment
		(start 466.213952 -96.407732)
		(end 464.951064 -95.144844)
		(width 0.12954)
		(layer "F.Cu")
		(net "FB_BMC_ISOLATE")
	)
	(segment
		(start 466.5345 -96.407732)
		(end 466.213952 -96.407732)
		(width 0.12954)
		(layer "F.Cu")
		(net "FB_BMC_ISOLATE")
	)
	(via
		(at 466.418676 -97.432368)
		(size 0.508)
		(drill 0.254)
		(layers "F.Cu" "B.Cu")
		(net "FB_BMC_ISOLATE")
	)
	(via
		(at 201.407522 -79.411068)
		(size 0.508)
		(drill 0.254)
		(layers "F.Cu" "B.Cu")
		(net "FB_BMC_ISOLATE")
	)
	(via
		(at 367.284 -17.221708)
		(size 0.508)
		(drill 0.254)
		(layers "F.Cu" "B.Cu")
		(net "FB_BMC_ISOLATE")
	)
	(via
		(at 463.882232 -95.144844)
		(size 0.762)
		(drill 0.381)
		(layers "F.Cu" "B.Cu")
		(net "FB_BMC_ISOLATE")
	)
	(via
		(at 219.30741 -113.240566)
		(size 0.508)
		(drill 0.254)
		(layers "F.Cu" "B.Cu")
		(net "FB_BMC_ISOLATE")
	)
	(via
		(at 195.54444 -76.825348)
		(size 0.508)
		(drill 0.254)
		(layers "F.Cu" "B.Cu")
		(net "FB_BMC_ISOLATE")
	)
	(via
		(at 283.92628 -115.857528)
		(size 0.508)
		(drill 0.254)
		(layers "F.Cu" "B.Cu")
		(net "FB_BMC_ISOLATE")
	)
	(via
		(at 373.31904 -114.965988)
		(size 0.508)
		(drill 0.254)
		(layers "F.Cu" "B.Cu")
		(net "FB_BMC_ISOLATE")
	)
	(segment
		(start 214.757 -71.502778)
		(end 215.64727 -71.502778)
		(width 0.12954)
		(layer "B.Cu")
		(net "FB_BMC_ISOLATE")
	)
	(segment
		(start 198.79056 -77.379068)
		(end 199.00646 -77.163168)
		(width 0.12954)
		(layer "B.Cu")
		(net "FB_BMC_ISOLATE")
	)
	(segment
		(start 215.8492 -69.764148)
		(end 215.6333 -69.548248)
		(width 0.12954)
		(layer "B.Cu")
		(net "FB_BMC_ISOLATE")
	)
	(segment
		(start 195.4149 -76.576428)
		(end 195.54444 -76.705968)
		(width 0.12954)
		(layer "B.Cu")
		(net "FB_BMC_ISOLATE")
	)
	(segment
		(start 208.935574 -68.923408)
		(end 208.915 -68.902834)
		(width 0.12954)
		(layer "B.Cu")
		(net "FB_BMC_ISOLATE")
	)
	(segment
		(start 207.4799 -68.555108)
		(end 207.827626 -68.902834)
		(width 0.12954)
		(layer "B.Cu")
		(net "FB_BMC_ISOLATE")
	)
	(segment
		(start 207.827626 -68.902834)
		(end 208.915 -68.902834)
		(width 0.12954)
		(layer "B.Cu")
		(net "FB_BMC_ISOLATE")
	)
	(segment
		(start 213.15426 -67.752468)
		(end 207.78724 -67.752468)
		(width 0.12954)
		(layer "B.Cu")
		(net "FB_BMC_ISOLATE")
	)
	(segment
		(start 219.241878 -79.24419)
		(end 218.28506 -80.201008)
		(width 0.12954)
		(layer "B.Cu")
		(net "FB_BMC_ISOLATE")
	)
	(segment
		(start 195.54444 -76.825348)
		(end 195.54444 -78.262988)
		(width 0.12954)
		(layer "B.Cu")
		(net "FB_BMC_ISOLATE")
	)
	(segment
		(start 213.14029 -71.502778)
		(end 212.63356 -72.009508)
		(width 0.12954)
		(layer "B.Cu")
		(net "FB_BMC_ISOLATE")
	)
	(segment
		(start 207.78724 -67.752468)
		(end 207.4799 -68.059808)
		(width 0.12954)
		(layer "B.Cu")
		(net "FB_BMC_ISOLATE")
	)
	(segment
		(start 218.28506 -80.201008)
		(end 202.197462 -80.201008)
		(width 0.12954)
		(layer "B.Cu")
		(net "FB_BMC_ISOLATE")
	)
	(segment
		(start 213.7664 -69.164708)
		(end 213.7664 -68.364608)
		(width 0.12954)
		(layer "B.Cu")
		(net "FB_BMC_ISOLATE")
	)
	(segment
		(start 212.63356 -73.005188)
		(end 214.48776 -74.859388)
		(width 0.12954)
		(layer "B.Cu")
		(net "FB_BMC_ISOLATE")
	)
	(segment
		(start 214.757 -71.502778)
		(end 213.14029 -71.502778)
		(width 0.12954)
		(layer "B.Cu")
		(net "FB_BMC_ISOLATE")
	)
	(segment
		(start 215.6333 -69.548248)
		(end 214.761572 -69.548248)
		(width 0.12954)
		(layer "B.Cu")
		(net "FB_BMC_ISOLATE")
	)
	(segment
		(start 194.304158 -76.542646)
		(end 194.33794 -76.576428)
		(width 0.12954)
		(layer "B.Cu")
		(net "FB_BMC_ISOLATE")
	)
	(segment
		(start 202.197462 -80.201008)
		(end 201.407522 -79.411068)
		(width 0.12954)
		(layer "B.Cu")
		(net "FB_BMC_ISOLATE")
	)
	(segment
		(start 218.16695 -77.07376)
		(end 219.241878 -78.148688)
		(width 0.12954)
		(layer "B.Cu")
		(net "FB_BMC_ISOLATE")
	)
	(segment
		(start 194.33794 -76.576428)
		(end 195.4149 -76.576428)
		(width 0.12954)
		(layer "B.Cu")
		(net "FB_BMC_ISOLATE")
	)
	(segment
		(start 201.139044 -79.14259)
		(end 200.146158 -79.14259)
		(width 0.12954)
		(layer "B.Cu")
		(net "FB_BMC_ISOLATE")
	)
	(segment
		(start 210.16214 -70.340728)
		(end 210.16214 -69.312028)
		(width 0.12954)
		(layer "B.Cu")
		(net "FB_BMC_ISOLATE")
	)
	(segment
		(start 215.8492 -71.300848)
		(end 215.8492 -69.764148)
		(width 0.12954)
		(layer "B.Cu")
		(net "FB_BMC_ISOLATE")
	)
	(segment
		(start 214.761572 -69.548248)
		(end 214.757 -69.55282)
		(width 0.12954)
		(layer "B.Cu")
		(net "FB_BMC_ISOLATE")
	)
	(segment
		(start 214.48776 -74.859388)
		(end 217.150188 -74.859388)
		(width 0.12954)
		(layer "B.Cu")
		(net "FB_BMC_ISOLATE")
	)
	(segment
		(start 200.146158 -79.14259)
		(end 199.050402 -79.14259)
		(width 0.12954)
		(layer "B.Cu")
		(net "FB_BMC_ISOLATE")
	)
	(segment
		(start 199.00646 -77.163168)
		(end 200.116694 -77.163168)
		(width 0.12954)
		(layer "B.Cu")
		(net "FB_BMC_ISOLATE")
	)
	(segment
		(start 213.7664 -68.364608)
		(end 213.15426 -67.752468)
		(width 0.12954)
		(layer "B.Cu")
		(net "FB_BMC_ISOLATE")
	)
	(segment
		(start 195.314824 -78.492604)
		(end 194.304158 -78.492604)
		(width 0.12954)
		(layer "B.Cu")
		(net "FB_BMC_ISOLATE")
	)
	(segment
		(start 195.54444 -76.705968)
		(end 195.54444 -76.825348)
		(width 0.12954)
		(layer "B.Cu")
		(net "FB_BMC_ISOLATE")
	)
	(segment
		(start 195.54444 -78.262988)
		(end 195.314824 -78.492604)
		(width 0.12954)
		(layer "B.Cu")
		(net "FB_BMC_ISOLATE")
	)
	(segment
		(start 217.150188 -74.859388)
		(end 218.16695 -75.87615)
		(width 0.12954)
		(layer "B.Cu")
		(net "FB_BMC_ISOLATE")
	)
	(segment
		(start 219.241878 -78.148688)
		(end 219.241878 -79.24419)
		(width 0.12954)
		(layer "B.Cu")
		(net "FB_BMC_ISOLATE")
	)
	(segment
		(start 208.915 -70.852792)
		(end 209.650076 -70.852792)
		(width 0.12954)
		(layer "B.Cu")
		(net "FB_BMC_ISOLATE")
	)
	(segment
		(start 201.407522 -79.411068)
		(end 201.139044 -79.14259)
		(width 0.12954)
		(layer "B.Cu")
		(net "FB_BMC_ISOLATE")
	)
	(segment
		(start 200.116694 -77.163168)
		(end 200.146158 -77.192632)
		(width 0.12954)
		(layer "B.Cu")
		(net "FB_BMC_ISOLATE")
	)
	(segment
		(start 214.757 -69.55282)
		(end 214.154512 -69.55282)
		(width 0.12954)
		(layer "B.Cu")
		(net "FB_BMC_ISOLATE")
	)
	(segment
		(start 207.4799 -68.059808)
		(end 207.4799 -68.555108)
		(width 0.12954)
		(layer "B.Cu")
		(net "FB_BMC_ISOLATE")
	)
	(segment
		(start 212.63356 -72.009508)
		(end 212.63356 -73.005188)
		(width 0.12954)
		(layer "B.Cu")
		(net "FB_BMC_ISOLATE")
	)
	(segment
		(start 215.64727 -71.502778)
		(end 215.8492 -71.300848)
		(width 0.12954)
		(layer "B.Cu")
		(net "FB_BMC_ISOLATE")
	)
	(segment
		(start 199.050402 -79.14259)
		(end 198.79056 -78.882748)
		(width 0.12954)
		(layer "B.Cu")
		(net "FB_BMC_ISOLATE")
	)
	(segment
		(start 210.16214 -69.312028)
		(end 209.77352 -68.923408)
		(width 0.12954)
		(layer "B.Cu")
		(net "FB_BMC_ISOLATE")
	)
	(segment
		(start 209.77352 -68.923408)
		(end 208.935574 -68.923408)
		(width 0.12954)
		(layer "B.Cu")
		(net "FB_BMC_ISOLATE")
	)
	(segment
		(start 214.154512 -69.55282)
		(end 213.7664 -69.164708)
		(width 0.12954)
		(layer "B.Cu")
		(net "FB_BMC_ISOLATE")
	)
	(segment
		(start 198.79056 -78.882748)
		(end 198.79056 -77.379068)
		(width 0.12954)
		(layer "B.Cu")
		(net "FB_BMC_ISOLATE")
	)
	(segment
		(start 209.650076 -70.852792)
		(end 210.16214 -70.340728)
		(width 0.12954)
		(layer "B.Cu")
		(net "FB_BMC_ISOLATE")
	)
	(segment
		(start 218.16695 -75.87615)
		(end 218.16695 -77.07376)
		(width 0.12954)
		(layer "B.Cu")
		(net "FB_BMC_ISOLATE")
	)
	(segment
		(start 380.55804 -97.132648)
		(end 381.99568 -95.695008)
		(width 0.127)
		(layer "In2.Cu")
		(net "FB_BMC_ISOLATE")
	)
	(segment
		(start 381.99568 -93.157548)
		(end 393.8778 -81.275428)
		(width 0.127)
		(layer "In2.Cu")
		(net "FB_BMC_ISOLATE")
	)
	(segment
		(start 375.6406 -108.524548)
		(end 376.01398 -108.151168)
		(width 0.127)
		(layer "In2.Cu")
		(net "FB_BMC_ISOLATE")
	)
	(segment
		(start 376.01398 -108.151168)
		(end 376.90552 -108.151168)
		(width 0.127)
		(layer "In2.Cu")
		(net "FB_BMC_ISOLATE")
	)
	(segment
		(start 380.55804 -104.259888)
		(end 380.55804 -97.132648)
		(width 0.127)
		(layer "In2.Cu")
		(net "FB_BMC_ISOLATE")
	)
	(segment
		(start 379.2601 -105.796588)
		(end 379.2601 -105.557828)
		(width 0.127)
		(layer "In2.Cu")
		(net "FB_BMC_ISOLATE")
	)
	(segment
		(start 389.90524 -70.769988)
		(end 389.90524 -67.343528)
		(width 0.127)
		(layer "In2.Cu")
		(net "FB_BMC_ISOLATE")
	)
	(segment
		(start 389.94588 -37.597588)
		(end 389.15594 -37.597588)
		(width 0.127)
		(layer "In2.Cu")
		(net "FB_BMC_ISOLATE")
	)
	(segment
		(start 393.8778 -74.742548)
		(end 389.90524 -70.769988)
		(width 0.127)
		(layer "In2.Cu")
		(net "FB_BMC_ISOLATE")
	)
	(segment
		(start 390.88822 -38.539928)
		(end 389.94588 -37.597588)
		(width 0.127)
		(layer "In2.Cu")
		(net "FB_BMC_ISOLATE")
	)
	(segment
		(start 379.2601 -105.557828)
		(end 380.55804 -104.259888)
		(width 0.127)
		(layer "In2.Cu")
		(net "FB_BMC_ISOLATE")
	)
	(segment
		(start 367.284 -28.077668)
		(end 367.284 -17.221708)
		(width 0.127)
		(layer "In2.Cu")
		(net "FB_BMC_ISOLATE")
	)
	(segment
		(start 391.28192 -49.992788)
		(end 390.88822 -49.599088)
		(width 0.127)
		(layer "In2.Cu")
		(net "FB_BMC_ISOLATE")
	)
	(segment
		(start 389.90524 -67.343528)
		(end 391.28192 -65.966848)
		(width 0.127)
		(layer "In2.Cu")
		(net "FB_BMC_ISOLATE")
	)
	(segment
		(start 377.58878 -38.382448)
		(end 367.284 -28.077668)
		(width 0.127)
		(layer "In2.Cu")
		(net "FB_BMC_ISOLATE")
	)
	(segment
		(start 388.37108 -38.382448)
		(end 377.58878 -38.382448)
		(width 0.127)
		(layer "In2.Cu")
		(net "FB_BMC_ISOLATE")
	)
	(segment
		(start 393.8778 -81.275428)
		(end 393.8778 -74.742548)
		(width 0.127)
		(layer "In2.Cu")
		(net "FB_BMC_ISOLATE")
	)
	(segment
		(start 391.28192 -65.966848)
		(end 391.28192 -49.992788)
		(width 0.127)
		(layer "In2.Cu")
		(net "FB_BMC_ISOLATE")
	)
	(segment
		(start 389.15594 -37.597588)
		(end 388.37108 -38.382448)
		(width 0.127)
		(layer "In2.Cu")
		(net "FB_BMC_ISOLATE")
	)
	(segment
		(start 376.90552 -108.151168)
		(end 379.2601 -105.796588)
		(width 0.127)
		(layer "In2.Cu")
		(net "FB_BMC_ISOLATE")
	)
	(segment
		(start 381.99568 -95.695008)
		(end 381.99568 -93.157548)
		(width 0.127)
		(layer "In2.Cu")
		(net "FB_BMC_ISOLATE")
	)
	(segment
		(start 373.31904 -114.965988)
		(end 375.6406 -112.644428)
		(width 0.127)
		(layer "In2.Cu")
		(net "FB_BMC_ISOLATE")
	)
	(segment
		(start 375.6406 -112.644428)
		(end 375.6406 -108.524548)
		(width 0.127)
		(layer "In2.Cu")
		(net "FB_BMC_ISOLATE")
	)
	(segment
		(start 390.88822 -49.599088)
		(end 390.88822 -38.539928)
		(width 0.127)
		(layer "In2.Cu")
		(net "FB_BMC_ISOLATE")
	)
	(segment
		(start 201.407522 -79.411068)
		(end 200.999598 -79.003144)
		(width 0.127)
		(layer "In6.Cu")
		(net "FB_BMC_ISOLATE")
	)
	(segment
		(start 223.574356 -111.88319)
		(end 236.49178 -111.88319)
		(width 0.127)
		(layer "In6.Cu")
		(net "FB_BMC_ISOLATE")
	)
	(segment
		(start 219.30741 -113.240566)
		(end 222.21698 -113.240566)
		(width 0.127)
		(layer "In6.Cu")
		(net "FB_BMC_ISOLATE")
	)
	(segment
		(start 200.999598 -79.003144)
		(end 197.722236 -79.003144)
		(width 0.127)
		(layer "In6.Cu")
		(net "FB_BMC_ISOLATE")
	)
	(segment
		(start 197.722236 -79.003144)
		(end 195.54444 -76.825348)
		(width 0.127)
		(layer "In6.Cu")
		(net "FB_BMC_ISOLATE")
	)
	(segment
		(start 237.704376 -113.095786)
		(end 240.380012 -113.095786)
		(width 0.127)
		(layer "In6.Cu")
		(net "FB_BMC_ISOLATE")
	)
	(segment
		(start 243.141754 -115.857528)
		(end 283.92628 -115.857528)
		(width 0.127)
		(layer "In6.Cu")
		(net "FB_BMC_ISOLATE")
	)
	(segment
		(start 240.380012 -113.095786)
		(end 243.141754 -115.857528)
		(width 0.127)
		(layer "In6.Cu")
		(net "FB_BMC_ISOLATE")
	)
	(segment
		(start 222.21698 -113.240566)
		(end 223.574356 -111.88319)
		(width 0.127)
		(layer "In6.Cu")
		(net "FB_BMC_ISOLATE")
	)
	(segment
		(start 236.49178 -111.88319)
		(end 237.704376 -113.095786)
		(width 0.127)
		(layer "In6.Cu")
		(net "FB_BMC_ISOLATE")
	)
	(segment
		(start 294.189658 -115.372896)
		(end 284.410912 -115.372896)
		(width 0.127)
		(layer "In13.Cu")
		(net "FB_BMC_ISOLATE")
	)
	(segment
		(start 371.834156 -114.220244)
		(end 324.506844 -114.220244)
		(width 0.127)
		(layer "In13.Cu")
		(net "FB_BMC_ISOLATE")
	)
	(segment
		(start 373.31904 -114.965988)
		(end 372.5799 -114.965988)
		(width 0.127)
		(layer "In13.Cu")
		(net "FB_BMC_ISOLATE")
	)
	(segment
		(start 458.45095 -97.021142)
		(end 455.17689 -97.021142)
		(width 0.127)
		(layer "In13.Cu")
		(net "FB_BMC_ISOLATE")
	)
	(segment
		(start 322.10502 -116.622068)
		(end 295.43883 -116.622068)
		(width 0.127)
		(layer "In13.Cu")
		(net "FB_BMC_ISOLATE")
	)
	(segment
		(start 295.43883 -116.622068)
		(end 294.189658 -115.372896)
		(width 0.127)
		(layer "In13.Cu")
		(net "FB_BMC_ISOLATE")
	)
	(segment
		(start 284.410912 -115.372896)
		(end 283.92628 -115.857528)
		(width 0.127)
		(layer "In13.Cu")
		(net "FB_BMC_ISOLATE")
	)
	(segment
		(start 324.506844 -114.220244)
		(end 322.10502 -116.622068)
		(width 0.127)
		(layer "In13.Cu")
		(net "FB_BMC_ISOLATE")
	)
	(segment
		(start 424.156886 -112.381538)
		(end 422.31818 -114.220244)
		(width 0.127)
		(layer "In13.Cu")
		(net "FB_BMC_ISOLATE")
	)
	(segment
		(start 455.17689 -97.021142)
		(end 439.816494 -112.381538)
		(width 0.127)
		(layer "In13.Cu")
		(net "FB_BMC_ISOLATE")
	)
	(segment
		(start 458.862176 -97.432368)
		(end 458.45095 -97.021142)
		(width 0.127)
		(layer "In13.Cu")
		(net "FB_BMC_ISOLATE")
	)
	(segment
		(start 466.418676 -97.432368)
		(end 458.862176 -97.432368)
		(width 0.127)
		(layer "In13.Cu")
		(net "FB_BMC_ISOLATE")
	)
	(segment
		(start 439.816494 -112.381538)
		(end 424.156886 -112.381538)
		(width 0.127)
		(layer "In13.Cu")
		(net "FB_BMC_ISOLATE")
	)
	(segment
		(start 374.577864 -114.220244)
		(end 373.83212 -114.965988)
		(width 0.127)
		(layer "In13.Cu")
		(net "FB_BMC_ISOLATE")
	)
	(segment
		(start 422.31818 -114.220244)
		(end 374.577864 -114.220244)
		(width 0.127)
		(layer "In13.Cu")
		(net "FB_BMC_ISOLATE")
	)
	(segment
		(start 373.83212 -114.965988)
		(end 373.31904 -114.965988)
		(width 0.127)
		(layer "In13.Cu")
		(net "FB_BMC_ISOLATE")
	)
	(segment
		(start 372.5799 -114.965988)
		(end 371.834156 -114.220244)
		(width 0.127)
		(layer "In13.Cu")
		(net "FB_BMC_ISOLATE")
	)
	(segment
		(start 300.1518 -47.488348)
		(end 300.1518 -47.945548)
		(width 0.12954)
		(layer "F.Cu")
		(net "FAB_REV_ID2")
	)
	(segment
		(start 299.42028 -47.288196)
		(end 299.42028 -48.304196)
		(width 0.12954)
		(layer "F.Cu")
		(net "FAB_REV_ID2")
	)
	(segment
		(start 299.793152 -48.304196)
		(end 299.42028 -48.304196)
		(width 0.12954)
		(layer "F.Cu")
		(net "FAB_REV_ID2")
	)
	(segment
		(start 329.165966 -49.859946)
		(end 329.437746 -49.390046)
		(width 0.12954)
		(layer "F.Cu")
		(net "FAB_REV_ID2")
	)
	(segment
		(start 300.1518 -47.945548)
		(end 299.793152 -48.304196)
		(width 0.12954)
		(layer "F.Cu")
		(net "FAB_REV_ID2")
	)
	(via
		(at 300.1518 -47.488348)
		(size 0.508)
		(drill 0.254)
		(layers "F.Cu" "B.Cu")
		(net "FAB_REV_ID2")
	)
	(via
		(at 329.437746 -49.390046)
		(size 0.4572)
		(drill 0.2032)
		(layers "F.Cu" "B.Cu")
		(net "FAB_REV_ID2")
	)
	(segment
		(start 315.11748 -49.113948)
		(end 315.06668 -49.164748)
		(width 0.127)
		(layer "In6.Cu")
		(net "FAB_REV_ID2")
	)
	(segment
		(start 311.8104 -46.797468)
		(end 307.7972 -46.797468)
		(width 0.127)
		(layer "In6.Cu")
		(net "FAB_REV_ID2")
	)
	(segment
		(start 321.40652 -47.843948)
		(end 320.13652 -49.113948)
		(width 0.127)
		(layer "In6.Cu")
		(net "FAB_REV_ID2")
	)
	(segment
		(start 315.06668 -49.164748)
		(end 314.17768 -49.164748)
		(width 0.127)
		(layer "In6.Cu")
		(net "FAB_REV_ID2")
	)
	(segment
		(start 307.7972 -46.797468)
		(end 306.82692 -45.827188)
		(width 0.127)
		(layer "In6.Cu")
		(net "FAB_REV_ID2")
	)
	(segment
		(start 320.13652 -49.113948)
		(end 315.11748 -49.113948)
		(width 0.127)
		(layer "In6.Cu")
		(net "FAB_REV_ID2")
	)
	(segment
		(start 329.437746 -49.390046)
		(end 329.437746 -49.474882)
		(width 0.127)
		(layer "In6.Cu")
		(net "FAB_REV_ID2")
	)
	(segment
		(start 301.81296 -45.827188)
		(end 300.1518 -47.488348)
		(width 0.127)
		(layer "In6.Cu")
		(net "FAB_REV_ID2")
	)
	(segment
		(start 314.17768 -49.164748)
		(end 311.8104 -46.797468)
		(width 0.127)
		(layer "In6.Cu")
		(net "FAB_REV_ID2")
	)
	(segment
		(start 329.03668 -49.875948)
		(end 327.41108 -49.875948)
		(width 0.127)
		(layer "In6.Cu")
		(net "FAB_REV_ID2")
	)
	(segment
		(start 325.37908 -47.843948)
		(end 321.40652 -47.843948)
		(width 0.127)
		(layer "In6.Cu")
		(net "FAB_REV_ID2")
	)
	(segment
		(start 329.437746 -49.474882)
		(end 329.03668 -49.875948)
		(width 0.127)
		(layer "In6.Cu")
		(net "FAB_REV_ID2")
	)
	(segment
		(start 306.82692 -45.827188)
		(end 301.81296 -45.827188)
		(width 0.127)
		(layer "In6.Cu")
		(net "FAB_REV_ID2")
	)
	(segment
		(start 327.41108 -49.875948)
		(end 325.37908 -47.843948)
		(width 0.127)
		(layer "In6.Cu")
		(net "FAB_REV_ID2")
	)
	(segment
		(start 322.56984 -74.812144)
		(end 322.8721 -75.114404)
		(width 0.12954)
		(layer "F.Cu")
		(net "FAB_REV_ID1")
	)
	(segment
		(start 322.8721 -75.114404)
		(end 322.8721 -76.185014)
		(width 0.12954)
		(layer "F.Cu")
		(net "FAB_REV_ID1")
	)
	(segment
		(start 332.549246 -49.390046)
		(end 332.422246 -49.517046)
		(width 0.12954)
		(layer "F.Cu")
		(net "FAB_REV_ID1")
	)
	(segment
		(start 332.693518 -49.390046)
		(end 332.549246 -49.390046)
		(width 0.12954)
		(layer "F.Cu")
		(net "FAB_REV_ID1")
	)
	(segment
		(start 332.422246 -49.517046)
		(end 332.422246 -49.859946)
		(width 0.12954)
		(layer "F.Cu")
		(net "FAB_REV_ID1")
	)
	(segment
		(start 321.8561 -76.185014)
		(end 322.8721 -76.185014)
		(width 0.12954)
		(layer "F.Cu")
		(net "FAB_REV_ID1")
	)
	(via
		(at 322.56984 -74.812144)
		(size 0.508)
		(drill 0.254)
		(layers "F.Cu" "B.Cu")
		(net "FAB_REV_ID1")
	)
	(via
		(at 332.693518 -49.390046)
		(size 0.4572)
		(drill 0.2032)
		(layers "F.Cu" "B.Cu")
		(net "FAB_REV_ID1")
	)
	(segment
		(start 332.49108 -55.540148)
		(end 332.18628 -55.844948)
		(width 0.127)
		(layer "In11.Cu")
		(net "FAB_REV_ID1")
	)
	(segment
		(start 332.08468 -56.886348)
		(end 332.08468 -59.629548)
		(width 0.127)
		(layer "In11.Cu")
		(net "FAB_REV_ID1")
	)
	(segment
		(start 333.22768 -49.875948)
		(end 333.22768 -50.442368)
		(width 0.127)
		(layer "In11.Cu")
		(net "FAB_REV_ID1")
	)
	(segment
		(start 331.60208 -60.112148)
		(end 331.60208 -64.836548)
		(width 0.127)
		(layer "In11.Cu")
		(net "FAB_REV_ID1")
	)
	(segment
		(start 332.18628 -56.098948)
		(end 332.41488 -56.327548)
		(width 0.127)
		(layer "In11.Cu")
		(net "FAB_REV_ID1")
	)
	(segment
		(start 331.60208 -64.836548)
		(end 326.64908 -69.789548)
		(width 0.127)
		(layer "In11.Cu")
		(net "FAB_REV_ID1")
	)
	(segment
		(start 332.741778 -49.390046)
		(end 333.22768 -49.875948)
		(width 0.127)
		(layer "In11.Cu")
		(net "FAB_REV_ID1")
	)
	(segment
		(start 332.08468 -59.629548)
		(end 331.60208 -60.112148)
		(width 0.127)
		(layer "In11.Cu")
		(net "FAB_REV_ID1")
	)
	(segment
		(start 333.25308 -52.898548)
		(end 333.25308 -53.889148)
		(width 0.127)
		(layer "In11.Cu")
		(net "FAB_REV_ID1")
	)
	(segment
		(start 332.64348 -52.288948)
		(end 333.25308 -52.898548)
		(width 0.127)
		(layer "In11.Cu")
		(net "FAB_REV_ID1")
	)
	(segment
		(start 326.64908 -69.789548)
		(end 326.64908 -70.732904)
		(width 0.127)
		(layer "In11.Cu")
		(net "FAB_REV_ID1")
	)
	(segment
		(start 326.64908 -70.732904)
		(end 322.56984 -74.812144)
		(width 0.127)
		(layer "In11.Cu")
		(net "FAB_REV_ID1")
	)
	(segment
		(start 332.18628 -55.844948)
		(end 332.18628 -56.098948)
		(width 0.127)
		(layer "In11.Cu")
		(net "FAB_REV_ID1")
	)
	(segment
		(start 332.41488 -56.556148)
		(end 332.08468 -56.886348)
		(width 0.127)
		(layer "In11.Cu")
		(net "FAB_REV_ID1")
	)
	(segment
		(start 332.693518 -49.390046)
		(end 332.741778 -49.390046)
		(width 0.127)
		(layer "In11.Cu")
		(net "FAB_REV_ID1")
	)
	(segment
		(start 332.41488 -56.327548)
		(end 332.41488 -56.556148)
		(width 0.127)
		(layer "In11.Cu")
		(net "FAB_REV_ID1")
	)
	(segment
		(start 332.49108 -54.651148)
		(end 332.49108 -55.540148)
		(width 0.127)
		(layer "In11.Cu")
		(net "FAB_REV_ID1")
	)
	(segment
		(start 333.25308 -53.889148)
		(end 332.49108 -54.651148)
		(width 0.127)
		(layer "In11.Cu")
		(net "FAB_REV_ID1")
	)
	(segment
		(start 332.64348 -51.026568)
		(end 332.64348 -52.288948)
		(width 0.127)
		(layer "In11.Cu")
		(net "FAB_REV_ID1")
	)
	(segment
		(start 333.22768 -50.442368)
		(end 332.64348 -51.026568)
		(width 0.127)
		(layer "In11.Cu")
		(net "FAB_REV_ID1")
	)
	(segment
		(start 329.165966 -53.619146)
		(end 328.62647 -53.619146)
		(width 0.12954)
		(layer "F.Cu")
		(net "FAB_REV_ID0")
	)
	(segment
		(start 300.59884 -52.156868)
		(end 300.59884 -51.763168)
		(width 0.12954)
		(layer "F.Cu")
		(net "FAB_REV_ID0")
	)
	(segment
		(start 299.42028 -52.368196)
		(end 299.42028 -51.352196)
		(width 0.12954)
		(layer "F.Cu")
		(net "FAB_REV_ID0")
	)
	(segment
		(start 300.187868 -51.352196)
		(end 299.42028 -51.352196)
		(width 0.12954)
		(layer "F.Cu")
		(net "FAB_REV_ID0")
	)
	(segment
		(start 300.59884 -51.763168)
		(end 300.187868 -51.352196)
		(width 0.12954)
		(layer "F.Cu")
		(net "FAB_REV_ID0")
	)
	(via
		(at 300.59884 -52.156868)
		(size 0.762)
		(drill 0.254)
		(layers "F.Cu" "B.Cu")
		(net "FAB_REV_ID0")
	)
	(via
		(at 328.62647 -53.619146)
		(size 0.4572)
		(drill 0.2032)
		(layers "F.Cu" "B.Cu")
		(net "FAB_REV_ID0")
	)
	(segment
		(start 321.61988 -54.524148)
		(end 318.74968 -54.524148)
		(width 0.127)
		(layer "In15.Cu")
		(net "FAB_REV_ID0")
	)
	(segment
		(start 315.04128 -55.235348)
		(end 314.55868 -55.717948)
		(width 0.127)
		(layer "In15.Cu")
		(net "FAB_REV_ID0")
	)
	(segment
		(start 323.75348 -55.006748)
		(end 322.10248 -55.006748)
		(width 0.127)
		(layer "In15.Cu")
		(net "FAB_REV_ID0")
	)
	(segment
		(start 318.74968 -54.524148)
		(end 318.03848 -55.235348)
		(width 0.127)
		(layer "In15.Cu")
		(net "FAB_REV_ID0")
	)
	(segment
		(start 324.05828 -54.701948)
		(end 323.75348 -55.006748)
		(width 0.127)
		(layer "In15.Cu")
		(net "FAB_REV_ID0")
	)
	(segment
		(start 313.36488 -55.717948)
		(end 313.11088 -55.971948)
		(width 0.127)
		(layer "In15.Cu")
		(net "FAB_REV_ID0")
	)
	(segment
		(start 314.55868 -55.717948)
		(end 313.36488 -55.717948)
		(width 0.127)
		(layer "In15.Cu")
		(net "FAB_REV_ID0")
	)
	(segment
		(start 322.10248 -55.006748)
		(end 321.61988 -54.524148)
		(width 0.127)
		(layer "In15.Cu")
		(net "FAB_REV_ID0")
	)
	(segment
		(start 326.24268 -54.701948)
		(end 324.05828 -54.701948)
		(width 0.127)
		(layer "In15.Cu")
		(net "FAB_REV_ID0")
	)
	(segment
		(start 313.11088 -55.971948)
		(end 305.7652 -55.971948)
		(width 0.127)
		(layer "In15.Cu")
		(net "FAB_REV_ID0")
	)
	(segment
		(start 327.325482 -53.619146)
		(end 326.24268 -54.701948)
		(width 0.127)
		(layer "In15.Cu")
		(net "FAB_REV_ID0")
	)
	(segment
		(start 328.62647 -53.619146)
		(end 327.325482 -53.619146)
		(width 0.127)
		(layer "In15.Cu")
		(net "FAB_REV_ID0")
	)
	(segment
		(start 300.59884 -52.342288)
		(end 300.59884 -52.156868)
		(width 0.127)
		(layer "In15.Cu")
		(net "FAB_REV_ID0")
	)
	(segment
		(start 304.0888 -54.295548)
		(end 302.5521 -54.295548)
		(width 0.127)
		(layer "In15.Cu")
		(net "FAB_REV_ID0")
	)
	(segment
		(start 318.03848 -55.235348)
		(end 315.04128 -55.235348)
		(width 0.127)
		(layer "In15.Cu")
		(net "FAB_REV_ID0")
	)
	(segment
		(start 305.7652 -55.971948)
		(end 304.0888 -54.295548)
		(width 0.127)
		(layer "In15.Cu")
		(net "FAB_REV_ID0")
	)
	(segment
		(start 302.5521 -54.295548)
		(end 300.59884 -52.342288)
		(width 0.127)
		(layer "In15.Cu")
		(net "FAB_REV_ID0")
	)
	(segment
		(start 174.66691 -16.550132)
		(end 174.66691 -17.465802)
		(width 0.12954)
		(layer "F.Cu")
		(net "ESPI_LPC_LAD0_IO3")
	)
	(segment
		(start 333.859124 -24.830024)
		(end 333.986124 -24.957024)
		(width 0.12954)
		(layer "F.Cu")
		(net "ESPI_LPC_LAD0_IO3")
	)
	(segment
		(start 174.66691 -17.465802)
		(end 174.666656 -17.466056)
		(width 0.12954)
		(layer "F.Cu")
		(net "ESPI_LPC_LAD0_IO3")
	)
	(segment
		(start 333.986124 -24.957024)
		(end 333.986124 -25.555956)
		(width 0.12954)
		(layer "F.Cu")
		(net "ESPI_LPC_LAD0_IO3")
	)
	(segment
		(start 174.666656 -17.466056)
		(end 174.666656 -18.593308)
		(width 0.12954)
		(layer "F.Cu")
		(net "ESPI_LPC_LAD0_IO3")
	)
	(via
		(at 333.859124 -24.830024)
		(size 0.508)
		(drill 0.254)
		(layers "F.Cu" "B.Cu")
		(net "ESPI_LPC_LAD0_IO3")
	)
	(via
		(at 174.666656 -18.593308)
		(size 0.508)
		(drill 0.254)
		(layers "F.Cu" "B.Cu")
		(net "ESPI_LPC_LAD0_IO3")
	)
	(segment
		(start 175.20412 -22.713188)
		(end 175.74768 -23.256748)
		(width 0.127)
		(layer "In6.Cu")
		(net "ESPI_LPC_LAD0_IO3")
	)
	(segment
		(start 325.727822 -28.264358)
		(end 329.569826 -28.264358)
		(width 0.127)
		(layer "In6.Cu")
		(net "ESPI_LPC_LAD0_IO3")
	)
	(segment
		(start 231.97058 -65.644268)
		(end 241.85245 -65.644268)
		(width 0.127)
		(layer "In6.Cu")
		(net "ESPI_LPC_LAD0_IO3")
	)
	(segment
		(start 265.632692 -60.223908)
		(end 272.583656 -60.223908)
		(width 0.127)
		(layer "In6.Cu")
		(net "ESPI_LPC_LAD0_IO3")
	)
	(segment
		(start 259.719572 -64.277748)
		(end 262.893556 -62.963044)
		(width 0.127)
		(layer "In6.Cu")
		(net "ESPI_LPC_LAD0_IO3")
	)
	(segment
		(start 329.569826 -28.264358)
		(end 332.364842 -25.469342)
		(width 0.127)
		(layer "In6.Cu")
		(net "ESPI_LPC_LAD0_IO3")
	)
	(segment
		(start 262.893556 -62.963044)
		(end 265.632692 -60.223908)
		(width 0.127)
		(layer "In6.Cu")
		(net "ESPI_LPC_LAD0_IO3")
	)
	(segment
		(start 193.731134 -30.160214)
		(end 202.750928 -39.180008)
		(width 0.127)
		(layer "In6.Cu")
		(net "ESPI_LPC_LAD0_IO3")
	)
	(segment
		(start 179.57038 -23.256748)
		(end 179.9971 -23.683468)
		(width 0.127)
		(layer "In6.Cu")
		(net "ESPI_LPC_LAD0_IO3")
	)
	(segment
		(start 188.11748 -23.673308)
		(end 191.17564 -26.731468)
		(width 0.127)
		(layer "In6.Cu")
		(net "ESPI_LPC_LAD0_IO3")
	)
	(segment
		(start 179.9971 -23.683468)
		(end 186.263026 -23.683468)
		(width 0.127)
		(layer "In6.Cu")
		(net "ESPI_LPC_LAD0_IO3")
	)
	(segment
		(start 191.17564 -26.731468)
		(end 191.17564 -28.174188)
		(width 0.127)
		(layer "In6.Cu")
		(net "ESPI_LPC_LAD0_IO3")
	)
	(segment
		(start 297.953176 -33.58388)
		(end 304.374804 -27.162252)
		(width 0.127)
		(layer "In6.Cu")
		(net "ESPI_LPC_LAD0_IO3")
	)
	(segment
		(start 243.21897 -64.277748)
		(end 259.719572 -64.277748)
		(width 0.127)
		(layer "In6.Cu")
		(net "ESPI_LPC_LAD0_IO3")
	)
	(segment
		(start 175.74768 -23.256748)
		(end 179.57038 -23.256748)
		(width 0.127)
		(layer "In6.Cu")
		(net "ESPI_LPC_LAD0_IO3")
	)
	(segment
		(start 202.750928 -39.180008)
		(end 212.807296 -39.180008)
		(width 0.127)
		(layer "In6.Cu")
		(net "ESPI_LPC_LAD0_IO3")
	)
	(segment
		(start 186.461146 -23.485348)
		(end 187.51296 -23.485348)
		(width 0.127)
		(layer "In6.Cu")
		(net "ESPI_LPC_LAD0_IO3")
	)
	(segment
		(start 193.161666 -30.160214)
		(end 193.731134 -30.160214)
		(width 0.127)
		(layer "In6.Cu")
		(net "ESPI_LPC_LAD0_IO3")
	)
	(segment
		(start 297.953176 -34.854388)
		(end 297.953176 -33.58388)
		(width 0.127)
		(layer "In6.Cu")
		(net "ESPI_LPC_LAD0_IO3")
	)
	(segment
		(start 187.70092 -23.673308)
		(end 188.11748 -23.673308)
		(width 0.127)
		(layer "In6.Cu")
		(net "ESPI_LPC_LAD0_IO3")
	)
	(segment
		(start 272.583656 -60.223908)
		(end 297.953176 -34.854388)
		(width 0.127)
		(layer "In6.Cu")
		(net "ESPI_LPC_LAD0_IO3")
	)
	(segment
		(start 332.364842 -25.469342)
		(end 333.219806 -25.469342)
		(width 0.127)
		(layer "In6.Cu")
		(net "ESPI_LPC_LAD0_IO3")
	)
	(segment
		(start 304.374804 -27.162252)
		(end 324.625716 -27.162252)
		(width 0.127)
		(layer "In6.Cu")
		(net "ESPI_LPC_LAD0_IO3")
	)
	(segment
		(start 216.41943 -42.792142)
		(end 216.41943 -50.093118)
		(width 0.127)
		(layer "In6.Cu")
		(net "ESPI_LPC_LAD0_IO3")
	)
	(segment
		(start 241.85245 -65.644268)
		(end 243.21897 -64.277748)
		(width 0.127)
		(layer "In6.Cu")
		(net "ESPI_LPC_LAD0_IO3")
	)
	(segment
		(start 186.263026 -23.683468)
		(end 186.461146 -23.485348)
		(width 0.127)
		(layer "In6.Cu")
		(net "ESPI_LPC_LAD0_IO3")
	)
	(segment
		(start 187.51296 -23.485348)
		(end 187.70092 -23.673308)
		(width 0.127)
		(layer "In6.Cu")
		(net "ESPI_LPC_LAD0_IO3")
	)
	(segment
		(start 174.666656 -18.593308)
		(end 174.666656 -18.936208)
		(width 0.127)
		(layer "In6.Cu")
		(net "ESPI_LPC_LAD0_IO3")
	)
	(segment
		(start 333.219806 -25.469342)
		(end 333.859124 -24.830024)
		(width 0.127)
		(layer "In6.Cu")
		(net "ESPI_LPC_LAD0_IO3")
	)
	(segment
		(start 174.666656 -18.936208)
		(end 175.20412 -19.473672)
		(width 0.127)
		(layer "In6.Cu")
		(net "ESPI_LPC_LAD0_IO3")
	)
	(segment
		(start 191.17564 -28.174188)
		(end 193.161666 -30.160214)
		(width 0.127)
		(layer "In6.Cu")
		(net "ESPI_LPC_LAD0_IO3")
	)
	(segment
		(start 212.807296 -39.180008)
		(end 216.41943 -42.792142)
		(width 0.127)
		(layer "In6.Cu")
		(net "ESPI_LPC_LAD0_IO3")
	)
	(segment
		(start 175.20412 -19.473672)
		(end 175.20412 -22.713188)
		(width 0.127)
		(layer "In6.Cu")
		(net "ESPI_LPC_LAD0_IO3")
	)
	(segment
		(start 324.625716 -27.162252)
		(end 325.727822 -28.264358)
		(width 0.127)
		(layer "In6.Cu")
		(net "ESPI_LPC_LAD0_IO3")
	)
	(segment
		(start 216.41943 -50.093118)
		(end 231.97058 -65.644268)
		(width 0.127)
		(layer "In6.Cu")
		(net "ESPI_LPC_LAD0_IO3")
	)
	(segment
		(start 175.266858 -16.550386)
		(end 175.266858 -17.816068)
		(width 0.12954)
		(layer "F.Cu")
		(net "ESPI_LPC_LAD0_IO2")
	)
	(segment
		(start 332.970124 -25.555956)
		(end 332.970124 -24.842978)
		(width 0.12954)
		(layer "F.Cu")
		(net "ESPI_LPC_LAD0_IO2")
	)
	(segment
		(start 175.267112 -16.550132)
		(end 175.266858 -16.550386)
		(width 0.12954)
		(layer "F.Cu")
		(net "ESPI_LPC_LAD0_IO2")
	)
	(via
		(at 332.970124 -24.842978)
		(size 0.508)
		(drill 0.254)
		(layers "F.Cu" "B.Cu")
		(net "ESPI_LPC_LAD0_IO2")
	)
	(via
		(at 175.266858 -17.816068)
		(size 0.508)
		(drill 0.254)
		(layers "F.Cu" "B.Cu")
		(net "ESPI_LPC_LAD0_IO2")
	)
	(segment
		(start 265.565382 -59.680348)
		(end 262.6487 -62.59703)
		(width 0.127)
		(layer "In6.Cu")
		(net "ESPI_LPC_LAD0_IO2")
	)
	(segment
		(start 259.633466 -63.845948)
		(end 243.0399 -63.845948)
		(width 0.127)
		(layer "In6.Cu")
		(net "ESPI_LPC_LAD0_IO2")
	)
	(segment
		(start 192.28308 -28.39212)
		(end 192.28308 -26.538428)
		(width 0.127)
		(layer "In6.Cu")
		(net "ESPI_LPC_LAD0_IO2")
	)
	(segment
		(start 189.74435 -23.999698)
		(end 189.74435 -22.772878)
		(width 0.127)
		(layer "In6.Cu")
		(net "ESPI_LPC_LAD0_IO2")
	)
	(segment
		(start 297.521376 -34.675318)
		(end 272.516346 -59.680348)
		(width 0.127)
		(layer "In6.Cu")
		(net "ESPI_LPC_LAD0_IO2")
	)
	(segment
		(start 175.74006 -19.08937)
		(end 175.266858 -18.616168)
		(width 0.127)
		(layer "In6.Cu")
		(net "ESPI_LPC_LAD0_IO2")
	)
	(segment
		(start 216.85123 -39.956232)
		(end 215.643206 -38.748208)
		(width 0.127)
		(layer "In6.Cu")
		(net "ESPI_LPC_LAD0_IO2")
	)
	(segment
		(start 329.72248 -27.396948)
		(end 328.452226 -27.396948)
		(width 0.127)
		(layer "In6.Cu")
		(net "ESPI_LPC_LAD0_IO2")
	)
	(segment
		(start 215.643206 -38.748208)
		(end 202.930252 -38.748208)
		(width 0.127)
		(layer "In6.Cu")
		(net "ESPI_LPC_LAD0_IO2")
	)
	(segment
		(start 327.258426 -26.203148)
		(end 324.00748 -26.203148)
		(width 0.127)
		(layer "In6.Cu")
		(net "ESPI_LPC_LAD0_IO2")
	)
	(segment
		(start 241.67338 -65.212468)
		(end 232.14965 -65.212468)
		(width 0.127)
		(layer "In6.Cu")
		(net "ESPI_LPC_LAD0_IO2")
	)
	(segment
		(start 216.85123 -49.914048)
		(end 216.85123 -39.956232)
		(width 0.127)
		(layer "In6.Cu")
		(net "ESPI_LPC_LAD0_IO2")
	)
	(segment
		(start 177.11928 -22.824948)
		(end 175.74006 -21.445728)
		(width 0.127)
		(layer "In6.Cu")
		(net "ESPI_LPC_LAD0_IO2")
	)
	(segment
		(start 192.28308 -26.538428)
		(end 189.74435 -23.999698)
		(width 0.127)
		(layer "In6.Cu")
		(net "ESPI_LPC_LAD0_IO2")
	)
	(segment
		(start 175.266858 -18.616168)
		(end 175.266858 -17.816068)
		(width 0.127)
		(layer "In6.Cu")
		(net "ESPI_LPC_LAD0_IO2")
	)
	(segment
		(start 262.6487 -62.59703)
		(end 259.633466 -63.845948)
		(width 0.127)
		(layer "In6.Cu")
		(net "ESPI_LPC_LAD0_IO2")
	)
	(segment
		(start 184.854596 -21.980652)
		(end 183.59882 -23.236428)
		(width 0.127)
		(layer "In6.Cu")
		(net "ESPI_LPC_LAD0_IO2")
	)
	(segment
		(start 243.0399 -63.845948)
		(end 241.67338 -65.212468)
		(width 0.127)
		(layer "In6.Cu")
		(net "ESPI_LPC_LAD0_IO2")
	)
	(segment
		(start 188.952124 -21.980652)
		(end 184.854596 -21.980652)
		(width 0.127)
		(layer "In6.Cu")
		(net "ESPI_LPC_LAD0_IO2")
	)
	(segment
		(start 272.516346 -59.680348)
		(end 265.565382 -59.680348)
		(width 0.127)
		(layer "In6.Cu")
		(net "ESPI_LPC_LAD0_IO2")
	)
	(segment
		(start 304.208942 -26.675334)
		(end 297.521376 -33.3629)
		(width 0.127)
		(layer "In6.Cu")
		(net "ESPI_LPC_LAD0_IO2")
	)
	(segment
		(start 324.00748 -26.203148)
		(end 323.535294 -26.675334)
		(width 0.127)
		(layer "In6.Cu")
		(net "ESPI_LPC_LAD0_IO2")
	)
	(segment
		(start 193.490088 -29.599128)
		(end 192.28308 -28.39212)
		(width 0.127)
		(layer "In6.Cu")
		(net "ESPI_LPC_LAD0_IO2")
	)
	(segment
		(start 323.535294 -26.675334)
		(end 304.208942 -26.675334)
		(width 0.127)
		(layer "In6.Cu")
		(net "ESPI_LPC_LAD0_IO2")
	)
	(segment
		(start 328.452226 -27.396948)
		(end 327.258426 -26.203148)
		(width 0.127)
		(layer "In6.Cu")
		(net "ESPI_LPC_LAD0_IO2")
	)
	(segment
		(start 189.74435 -22.772878)
		(end 188.952124 -21.980652)
		(width 0.127)
		(layer "In6.Cu")
		(net "ESPI_LPC_LAD0_IO2")
	)
	(segment
		(start 332.27645 -24.842978)
		(end 329.72248 -27.396948)
		(width 0.127)
		(layer "In6.Cu")
		(net "ESPI_LPC_LAD0_IO2")
	)
	(segment
		(start 180.182266 -23.236428)
		(end 179.770786 -22.824948)
		(width 0.127)
		(layer "In6.Cu")
		(net "ESPI_LPC_LAD0_IO2")
	)
	(segment
		(start 297.521376 -33.3629)
		(end 297.521376 -34.675318)
		(width 0.127)
		(layer "In6.Cu")
		(net "ESPI_LPC_LAD0_IO2")
	)
	(segment
		(start 202.930252 -38.748208)
		(end 193.781172 -29.599128)
		(width 0.127)
		(layer "In6.Cu")
		(net "ESPI_LPC_LAD0_IO2")
	)
	(segment
		(start 183.59882 -23.236428)
		(end 180.182266 -23.236428)
		(width 0.127)
		(layer "In6.Cu")
		(net "ESPI_LPC_LAD0_IO2")
	)
	(segment
		(start 332.970124 -24.842978)
		(end 332.27645 -24.842978)
		(width 0.127)
		(layer "In6.Cu")
		(net "ESPI_LPC_LAD0_IO2")
	)
	(segment
		(start 175.74006 -21.445728)
		(end 175.74006 -19.08937)
		(width 0.127)
		(layer "In6.Cu")
		(net "ESPI_LPC_LAD0_IO2")
	)
	(segment
		(start 193.781172 -29.599128)
		(end 193.490088 -29.599128)
		(width 0.127)
		(layer "In6.Cu")
		(net "ESPI_LPC_LAD0_IO2")
	)
	(segment
		(start 232.14965 -65.212468)
		(end 216.85123 -49.914048)
		(width 0.127)
		(layer "In6.Cu")
		(net "ESPI_LPC_LAD0_IO2")
	)
	(segment
		(start 179.770786 -22.824948)
		(end 177.11928 -22.824948)
		(width 0.127)
		(layer "In6.Cu")
		(net "ESPI_LPC_LAD0_IO2")
	)
	(segment
		(start 175.86706 -17.465802)
		(end 175.866806 -17.466056)
		(width 0.12954)
		(layer "F.Cu")
		(net "ESPI_LPC_LAD0_IO1")
	)
	(segment
		(start 175.86706 -16.550132)
		(end 175.86706 -17.465802)
		(width 0.12954)
		(layer "F.Cu")
		(net "ESPI_LPC_LAD0_IO1")
	)
	(segment
		(start 335.002124 -25.229312)
		(end 335.002124 -25.554432)
		(width 0.12954)
		(layer "F.Cu")
		(net "ESPI_LPC_LAD0_IO1")
	)
	(segment
		(start 335.271872 -24.959564)
		(end 335.002124 -25.229312)
		(width 0.12954)
		(layer "F.Cu")
		(net "ESPI_LPC_LAD0_IO1")
	)
	(segment
		(start 175.866806 -17.466056)
		(end 175.866806 -18.463768)
		(width 0.12954)
		(layer "F.Cu")
		(net "ESPI_LPC_LAD0_IO1")
	)
	(via
		(at 175.866806 -18.463768)
		(size 0.508)
		(drill 0.254)
		(layers "F.Cu" "B.Cu")
		(net "ESPI_LPC_LAD0_IO1")
	)
	(via
		(at 335.271872 -24.959564)
		(size 0.508)
		(drill 0.254)
		(layers "F.Cu" "B.Cu")
		(net "ESPI_LPC_LAD0_IO1")
	)
	(segment
		(start 215.15832 -42.141902)
		(end 215.98763 -44.14393)
		(width 0.127)
		(layer "In6.Cu")
		(net "ESPI_LPC_LAD0_IO1")
	)
	(segment
		(start 242.03152 -66.076068)
		(end 243.39804 -64.709548)
		(width 0.127)
		(layer "In6.Cu")
		(net "ESPI_LPC_LAD0_IO1")
	)
	(segment
		(start 323.288914 -28.034488)
		(end 324.64121 -28.034488)
		(width 0.127)
		(layer "In6.Cu")
		(net "ESPI_LPC_LAD0_IO1")
	)
	(segment
		(start 193.611246 -30.762702)
		(end 202.460352 -39.611808)
		(width 0.127)
		(layer "In6.Cu")
		(net "ESPI_LPC_LAD0_IO1")
	)
	(segment
		(start 190.5 -27.934666)
		(end 190.5 -28.235148)
		(width 0.127)
		(layer "In6.Cu")
		(net "ESPI_LPC_LAD0_IO1")
	)
	(segment
		(start 175.380396 -17.264888)
		(end 173.19498 -17.264888)
		(width 0.127)
		(layer "In6.Cu")
		(net "ESPI_LPC_LAD0_IO1")
	)
	(segment
		(start 321.005454 -30.317948)
		(end 323.288914 -28.034488)
		(width 0.127)
		(layer "In6.Cu")
		(net "ESPI_LPC_LAD0_IO1")
	)
	(segment
		(start 307.365654 -30.218634)
		(end 319.706244 -30.218634)
		(width 0.127)
		(layer "In6.Cu")
		(net "ESPI_LPC_LAD0_IO1")
	)
	(segment
		(start 259.805678 -64.709548)
		(end 263.138666 -63.329058)
		(width 0.127)
		(layer "In6.Cu")
		(net "ESPI_LPC_LAD0_IO1")
	)
	(segment
		(start 202.460352 -39.611808)
		(end 212.628226 -39.611808)
		(width 0.127)
		(layer "In6.Cu")
		(net "ESPI_LPC_LAD0_IO1")
	)
	(segment
		(start 179.77866 -24.120348)
		(end 185.956956 -24.120348)
		(width 0.127)
		(layer "In6.Cu")
		(net "ESPI_LPC_LAD0_IO1")
	)
	(segment
		(start 175.866806 -18.463768)
		(end 175.866806 -17.751298)
		(width 0.127)
		(layer "In6.Cu")
		(net "ESPI_LPC_LAD0_IO1")
	)
	(segment
		(start 185.956956 -24.120348)
		(end 186.449716 -24.613108)
		(width 0.127)
		(layer "In6.Cu")
		(net "ESPI_LPC_LAD0_IO1")
	)
	(segment
		(start 215.98763 -50.272188)
		(end 231.79151 -66.076068)
		(width 0.127)
		(layer "In6.Cu")
		(net "ESPI_LPC_LAD0_IO1")
	)
	(segment
		(start 171.99356 -20.137882)
		(end 175.544226 -23.688548)
		(width 0.127)
		(layer "In6.Cu")
		(net "ESPI_LPC_LAD0_IO1")
	)
	(segment
		(start 186.449716 -24.613108)
		(end 188.309504 -24.613108)
		(width 0.127)
		(layer "In6.Cu")
		(net "ESPI_LPC_LAD0_IO1")
	)
	(segment
		(start 319.805558 -30.317948)
		(end 321.005454 -30.317948)
		(width 0.127)
		(layer "In6.Cu")
		(net "ESPI_LPC_LAD0_IO1")
	)
	(segment
		(start 175.544226 -23.688548)
		(end 179.34686 -23.688548)
		(width 0.127)
		(layer "In6.Cu")
		(net "ESPI_LPC_LAD0_IO1")
	)
	(segment
		(start 325.30288 -28.696158)
		(end 329.74915 -28.696158)
		(width 0.127)
		(layer "In6.Cu")
		(net "ESPI_LPC_LAD0_IO1")
	)
	(segment
		(start 175.866806 -17.751298)
		(end 175.380396 -17.264888)
		(width 0.127)
		(layer "In6.Cu")
		(net "ESPI_LPC_LAD0_IO1")
	)
	(segment
		(start 319.706244 -30.218634)
		(end 319.805558 -30.317948)
		(width 0.127)
		(layer "In6.Cu")
		(net "ESPI_LPC_LAD0_IO1")
	)
	(segment
		(start 190.5 -28.235148)
		(end 193.027554 -30.762702)
		(width 0.127)
		(layer "In6.Cu")
		(net "ESPI_LPC_LAD0_IO1")
	)
	(segment
		(start 231.79151 -66.076068)
		(end 242.03152 -66.076068)
		(width 0.127)
		(layer "In6.Cu")
		(net "ESPI_LPC_LAD0_IO1")
	)
	(segment
		(start 179.34686 -23.688548)
		(end 179.77866 -24.120348)
		(width 0.127)
		(layer "In6.Cu")
		(net "ESPI_LPC_LAD0_IO1")
	)
	(segment
		(start 189.6999 -26.003504)
		(end 190.5 -27.934666)
		(width 0.127)
		(layer "In6.Cu")
		(net "ESPI_LPC_LAD0_IO1")
	)
	(segment
		(start 324.64121 -28.034488)
		(end 325.30288 -28.696158)
		(width 0.127)
		(layer "In6.Cu")
		(net "ESPI_LPC_LAD0_IO1")
	)
	(segment
		(start 273.037808 -60.66028)
		(end 302.64862 -31.049468)
		(width 0.127)
		(layer "In6.Cu")
		(net "ESPI_LPC_LAD0_IO1")
	)
	(segment
		(start 265.807444 -60.66028)
		(end 273.037808 -60.66028)
		(width 0.127)
		(layer "In6.Cu")
		(net "ESPI_LPC_LAD0_IO1")
	)
	(segment
		(start 243.39804 -64.709548)
		(end 259.805678 -64.709548)
		(width 0.127)
		(layer "In6.Cu")
		(net "ESPI_LPC_LAD0_IO1")
	)
	(segment
		(start 173.19498 -17.264888)
		(end 171.99356 -18.466308)
		(width 0.127)
		(layer "In6.Cu")
		(net "ESPI_LPC_LAD0_IO1")
	)
	(segment
		(start 330.33716 -28.108148)
		(end 332.123288 -28.108148)
		(width 0.127)
		(layer "In6.Cu")
		(net "ESPI_LPC_LAD0_IO1")
	)
	(segment
		(start 306.53482 -31.049468)
		(end 307.365654 -30.218634)
		(width 0.127)
		(layer "In6.Cu")
		(net "ESPI_LPC_LAD0_IO1")
	)
	(segment
		(start 302.64862 -31.049468)
		(end 306.53482 -31.049468)
		(width 0.127)
		(layer "In6.Cu")
		(net "ESPI_LPC_LAD0_IO1")
	)
	(segment
		(start 193.027554 -30.762702)
		(end 193.611246 -30.762702)
		(width 0.127)
		(layer "In6.Cu")
		(net "ESPI_LPC_LAD0_IO1")
	)
	(segment
		(start 329.74915 -28.696158)
		(end 330.33716 -28.108148)
		(width 0.127)
		(layer "In6.Cu")
		(net "ESPI_LPC_LAD0_IO1")
	)
	(segment
		(start 212.628226 -39.611808)
		(end 215.15832 -42.141902)
		(width 0.127)
		(layer "In6.Cu")
		(net "ESPI_LPC_LAD0_IO1")
	)
	(segment
		(start 171.99356 -18.466308)
		(end 171.99356 -20.137882)
		(width 0.127)
		(layer "In6.Cu")
		(net "ESPI_LPC_LAD0_IO1")
	)
	(segment
		(start 188.309504 -24.613108)
		(end 189.6999 -26.003504)
		(width 0.127)
		(layer "In6.Cu")
		(net "ESPI_LPC_LAD0_IO1")
	)
	(segment
		(start 263.138666 -63.329058)
		(end 265.807444 -60.66028)
		(width 0.127)
		(layer "In6.Cu")
		(net "ESPI_LPC_LAD0_IO1")
	)
	(segment
		(start 215.98763 -44.14393)
		(end 215.98763 -50.272188)
		(width 0.127)
		(layer "In6.Cu")
		(net "ESPI_LPC_LAD0_IO1")
	)
	(segment
		(start 332.123288 -28.108148)
		(end 335.271872 -24.959564)
		(width 0.127)
		(layer "In6.Cu")
		(net "ESPI_LPC_LAD0_IO1")
	)
	(segment
		(start 328.39152 -23.663148)
		(end 328.865484 -23.663148)
		(width 0.12954)
		(layer "F.Cu")
		(net "ESPI_LPC_LAD0_IO0")
	)
	(segment
		(start 176.467008 -16.550132)
		(end 176.466754 -16.550386)
		(width 0.12954)
		(layer "F.Cu")
		(net "ESPI_LPC_LAD0_IO0")
	)
	(segment
		(start 176.466754 -16.550386)
		(end 176.466754 -17.833848)
		(width 0.12954)
		(layer "F.Cu")
		(net "ESPI_LPC_LAD0_IO0")
	)
	(segment
		(start 328.865484 -23.663148)
		(end 329.124818 -23.403814)
		(width 0.12954)
		(layer "F.Cu")
		(net "ESPI_LPC_LAD0_IO0")
	)
	(via
		(at 328.39152 -23.663148)
		(size 0.508)
		(drill 0.254)
		(layers "F.Cu" "B.Cu")
		(net "ESPI_LPC_LAD0_IO0")
	)
	(via
		(at 176.466754 -17.833848)
		(size 0.508)
		(drill 0.254)
		(layers "F.Cu" "B.Cu")
		(net "ESPI_LPC_LAD0_IO0")
	)
	(segment
		(start 321.765422 -24.399748)
		(end 321.638422 -24.526748)
		(width 0.127)
		(layer "In6.Cu")
		(net "ESPI_LPC_LAD0_IO0")
	)
	(segment
		(start 179.17414 -20.74164)
		(end 178.909472 -21.006308)
		(width 0.127)
		(layer "In6.Cu")
		(net "ESPI_LPC_LAD0_IO0")
	)
	(segment
		(start 296.657776 -34.18459)
		(end 272.119598 -58.722768)
		(width 0.127)
		(layer "In6.Cu")
		(net "ESPI_LPC_LAD0_IO0")
	)
	(segment
		(start 178.5239 -20.0914)
		(end 178.259232 -20.356068)
		(width 0.127)
		(layer "In6.Cu")
		(net "ESPI_LPC_LAD0_IO0")
	)
	(segment
		(start 181.75478 -21.648928)
		(end 180.26126 -21.648928)
		(width 0.127)
		(layer "In6.Cu")
		(net "ESPI_LPC_LAD0_IO0")
	)
	(segment
		(start 178.84902 -20.236688)
		(end 178.703732 -20.0914)
		(width 0.127)
		(layer "In6.Cu")
		(net "ESPI_LPC_LAD0_IO0")
	)
	(segment
		(start 217.71483 -49.555146)
		(end 217.71483 -39.567612)
		(width 0.127)
		(layer "In6.Cu")
		(net "ESPI_LPC_LAD0_IO0")
	)
	(segment
		(start 323.477382 -24.526748)
		(end 323.477382 -25.032208)
		(width 0.127)
		(layer "In6.Cu")
		(net "ESPI_LPC_LAD0_IO0")
	)
	(segment
		(start 265.300714 -58.722768)
		(end 262.158734 -61.864748)
		(width 0.127)
		(layer "In6.Cu")
		(net "ESPI_LPC_LAD0_IO0")
	)
	(segment
		(start 178.259232 -20.356068)
		(end 178.0794 -20.356068)
		(width 0.127)
		(layer "In6.Cu")
		(net "ESPI_LPC_LAD0_IO0")
	)
	(segment
		(start 259.460746 -62.982348)
		(end 242.68176 -62.982348)
		(width 0.127)
		(layer "In6.Cu")
		(net "ESPI_LPC_LAD0_IO0")
	)
	(segment
		(start 326.89546 -25.159208)
		(end 324.064122 -25.159208)
		(width 0.127)
		(layer "In6.Cu")
		(net "ESPI_LPC_LAD0_IO0")
	)
	(segment
		(start 177.05832 -17.833848)
		(end 176.466754 -17.833848)
		(width 0.127)
		(layer "In6.Cu")
		(net "ESPI_LPC_LAD0_IO0")
	)
	(segment
		(start 321.638422 -24.526748)
		(end 321.638422 -24.9682)
		(width 0.127)
		(layer "In6.Cu")
		(net "ESPI_LPC_LAD0_IO0")
	)
	(segment
		(start 178.909472 -21.006308)
		(end 178.72964 -21.006308)
		(width 0.127)
		(layer "In6.Cu")
		(net "ESPI_LPC_LAD0_IO0")
	)
	(segment
		(start 184.17794 -21.176488)
		(end 182.22722 -21.176488)
		(width 0.127)
		(layer "In6.Cu")
		(net "ESPI_LPC_LAD0_IO0")
	)
	(segment
		(start 179.353972 -20.74164)
		(end 179.17414 -20.74164)
		(width 0.127)
		(layer "In6.Cu")
		(net "ESPI_LPC_LAD0_IO0")
	)
	(segment
		(start 211.223606 -33.076388)
		(end 198.480426 -33.076388)
		(width 0.127)
		(layer "In6.Cu")
		(net "ESPI_LPC_LAD0_IO0")
	)
	(segment
		(start 323.350382 -25.159208)
		(end 323.144642 -25.159208)
		(width 0.127)
		(layer "In6.Cu")
		(net "ESPI_LPC_LAD0_IO0")
	)
	(segment
		(start 232.508552 -64.348868)
		(end 217.71483 -49.555146)
		(width 0.127)
		(layer "In6.Cu")
		(net "ESPI_LPC_LAD0_IO0")
	)
	(segment
		(start 323.144642 -25.159208)
		(end 323.017642 -25.032208)
		(width 0.127)
		(layer "In6.Cu")
		(net "ESPI_LPC_LAD0_IO0")
	)
	(segment
		(start 323.604382 -24.399748)
		(end 323.477382 -24.526748)
		(width 0.127)
		(layer "In6.Cu")
		(net "ESPI_LPC_LAD0_IO0")
	)
	(segment
		(start 177.46726 -18.242788)
		(end 177.05832 -17.833848)
		(width 0.127)
		(layer "In6.Cu")
		(net "ESPI_LPC_LAD0_IO0")
	)
	(segment
		(start 177.419 -19.695668)
		(end 177.419 -18.733008)
		(width 0.127)
		(layer "In6.Cu")
		(net "ESPI_LPC_LAD0_IO0")
	)
	(segment
		(start 178.72964 -21.006308)
		(end 178.584352 -20.86102)
		(width 0.127)
		(layer "In6.Cu")
		(net "ESPI_LPC_LAD0_IO0")
	)
	(segment
		(start 178.584352 -20.86102)
		(end 178.584352 -20.681188)
		(width 0.127)
		(layer "In6.Cu")
		(net "ESPI_LPC_LAD0_IO0")
	)
	(segment
		(start 184.90438 -20.450048)
		(end 184.17794 -21.176488)
		(width 0.127)
		(layer "In6.Cu")
		(net "ESPI_LPC_LAD0_IO0")
	)
	(segment
		(start 177.46726 -18.684748)
		(end 177.46726 -18.242788)
		(width 0.127)
		(layer "In6.Cu")
		(net "ESPI_LPC_LAD0_IO0")
	)
	(segment
		(start 193.355722 -23.163276)
		(end 190.642494 -20.450048)
		(width 0.127)
		(layer "In6.Cu")
		(net "ESPI_LPC_LAD0_IO0")
	)
	(segment
		(start 180.26126 -21.648928)
		(end 179.353972 -20.74164)
		(width 0.127)
		(layer "In6.Cu")
		(net "ESPI_LPC_LAD0_IO0")
	)
	(segment
		(start 178.703732 -20.0914)
		(end 178.5239 -20.0914)
		(width 0.127)
		(layer "In6.Cu")
		(net "ESPI_LPC_LAD0_IO0")
	)
	(segment
		(start 322.890642 -24.399748)
		(end 322.684902 -24.399748)
		(width 0.127)
		(layer "In6.Cu")
		(net "ESPI_LPC_LAD0_IO0")
	)
	(segment
		(start 262.158734 -61.864748)
		(end 259.460746 -62.982348)
		(width 0.127)
		(layer "In6.Cu")
		(net "ESPI_LPC_LAD0_IO0")
	)
	(segment
		(start 182.22722 -21.176488)
		(end 181.75478 -21.648928)
		(width 0.127)
		(layer "In6.Cu")
		(net "ESPI_LPC_LAD0_IO0")
	)
	(segment
		(start 323.937122 -25.032208)
		(end 323.937122 -24.526748)
		(width 0.127)
		(layer "In6.Cu")
		(net "ESPI_LPC_LAD0_IO0")
	)
	(segment
		(start 190.642494 -20.450048)
		(end 184.90438 -20.450048)
		(width 0.127)
		(layer "In6.Cu")
		(net "ESPI_LPC_LAD0_IO0")
	)
	(segment
		(start 323.017642 -24.526748)
		(end 322.890642 -24.399748)
		(width 0.127)
		(layer "In6.Cu")
		(net "ESPI_LPC_LAD0_IO0")
	)
	(segment
		(start 324.064122 -25.159208)
		(end 323.937122 -25.032208)
		(width 0.127)
		(layer "In6.Cu")
		(net "ESPI_LPC_LAD0_IO0")
	)
	(segment
		(start 322.225162 -25.159208)
		(end 322.098162 -25.032208)
		(width 0.127)
		(layer "In6.Cu")
		(net "ESPI_LPC_LAD0_IO0")
	)
	(segment
		(start 323.477382 -25.032208)
		(end 323.350382 -25.159208)
		(width 0.127)
		(layer "In6.Cu")
		(net "ESPI_LPC_LAD0_IO0")
	)
	(segment
		(start 322.557902 -25.032208)
		(end 322.430902 -25.159208)
		(width 0.127)
		(layer "In6.Cu")
		(net "ESPI_LPC_LAD0_IO0")
	)
	(segment
		(start 178.584352 -20.681188)
		(end 178.84902 -20.41652)
		(width 0.127)
		(layer "In6.Cu")
		(net "ESPI_LPC_LAD0_IO0")
	)
	(segment
		(start 198.480426 -33.076388)
		(end 194.416426 -29.012388)
		(width 0.127)
		(layer "In6.Cu")
		(net "ESPI_LPC_LAD0_IO0")
	)
	(segment
		(start 322.098162 -25.032208)
		(end 322.098162 -24.526748)
		(width 0.127)
		(layer "In6.Cu")
		(net "ESPI_LPC_LAD0_IO0")
	)
	(segment
		(start 323.810122 -24.399748)
		(end 323.604382 -24.399748)
		(width 0.127)
		(layer "In6.Cu")
		(net "ESPI_LPC_LAD0_IO0")
	)
	(segment
		(start 194.416426 -29.012388)
		(end 193.355722 -26.45156)
		(width 0.127)
		(layer "In6.Cu")
		(net "ESPI_LPC_LAD0_IO0")
	)
	(segment
		(start 296.657776 -32.852106)
		(end 296.657776 -34.18459)
		(width 0.127)
		(layer "In6.Cu")
		(net "ESPI_LPC_LAD0_IO0")
	)
	(segment
		(start 321.971162 -24.399748)
		(end 321.765422 -24.399748)
		(width 0.127)
		(layer "In6.Cu")
		(net "ESPI_LPC_LAD0_IO0")
	)
	(segment
		(start 242.68176 -62.982348)
		(end 241.31524 -64.348868)
		(width 0.127)
		(layer "In6.Cu")
		(net "ESPI_LPC_LAD0_IO0")
	)
	(segment
		(start 323.937122 -24.526748)
		(end 323.810122 -24.399748)
		(width 0.127)
		(layer "In6.Cu")
		(net "ESPI_LPC_LAD0_IO0")
	)
	(segment
		(start 322.557902 -24.526748)
		(end 322.557902 -25.032208)
		(width 0.127)
		(layer "In6.Cu")
		(net "ESPI_LPC_LAD0_IO0")
	)
	(segment
		(start 178.84902 -20.41652)
		(end 178.84902 -20.236688)
		(width 0.127)
		(layer "In6.Cu")
		(net "ESPI_LPC_LAD0_IO0")
	)
	(segment
		(start 322.684902 -24.399748)
		(end 322.557902 -24.526748)
		(width 0.127)
		(layer "In6.Cu")
		(net "ESPI_LPC_LAD0_IO0")
	)
	(segment
		(start 323.017642 -25.032208)
		(end 323.017642 -24.526748)
		(width 0.127)
		(layer "In6.Cu")
		(net "ESPI_LPC_LAD0_IO0")
	)
	(segment
		(start 322.098162 -24.526748)
		(end 321.971162 -24.399748)
		(width 0.127)
		(layer "In6.Cu")
		(net "ESPI_LPC_LAD0_IO0")
	)
	(segment
		(start 322.430902 -25.159208)
		(end 322.225162 -25.159208)
		(width 0.127)
		(layer "In6.Cu")
		(net "ESPI_LPC_LAD0_IO0")
	)
	(segment
		(start 319.476628 -25.0952)
		(end 318.760094 -25.811734)
		(width 0.127)
		(layer "In6.Cu")
		(net "ESPI_LPC_LAD0_IO0")
	)
	(segment
		(start 318.760094 -25.811734)
		(end 303.698148 -25.811734)
		(width 0.127)
		(layer "In6.Cu")
		(net "ESPI_LPC_LAD0_IO0")
	)
	(segment
		(start 241.31524 -64.348868)
		(end 232.508552 -64.348868)
		(width 0.127)
		(layer "In6.Cu")
		(net "ESPI_LPC_LAD0_IO0")
	)
	(segment
		(start 321.511422 -25.0952)
		(end 319.476628 -25.0952)
		(width 0.127)
		(layer "In6.Cu")
		(net "ESPI_LPC_LAD0_IO0")
	)
	(segment
		(start 217.71483 -39.567612)
		(end 211.223606 -33.076388)
		(width 0.127)
		(layer "In6.Cu")
		(net "ESPI_LPC_LAD0_IO0")
	)
	(segment
		(start 178.0794 -20.356068)
		(end 177.419 -19.695668)
		(width 0.127)
		(layer "In6.Cu")
		(net "ESPI_LPC_LAD0_IO0")
	)
	(segment
		(start 193.355722 -26.45156)
		(end 193.355722 -23.163276)
		(width 0.127)
		(layer "In6.Cu")
		(net "ESPI_LPC_LAD0_IO0")
	)
	(segment
		(start 272.119598 -58.722768)
		(end 265.300714 -58.722768)
		(width 0.127)
		(layer "In6.Cu")
		(net "ESPI_LPC_LAD0_IO0")
	)
	(segment
		(start 328.39152 -23.663148)
		(end 326.89546 -25.159208)
		(width 0.127)
		(layer "In6.Cu")
		(net "ESPI_LPC_LAD0_IO0")
	)
	(segment
		(start 303.698148 -25.811734)
		(end 296.657776 -32.852106)
		(width 0.127)
		(layer "In6.Cu")
		(net "ESPI_LPC_LAD0_IO0")
	)
	(segment
		(start 321.638422 -24.9682)
		(end 321.511422 -25.0952)
		(width 0.127)
		(layer "In6.Cu")
		(net "ESPI_LPC_LAD0_IO0")
	)
	(segment
		(start 177.419 -18.733008)
		(end 177.46726 -18.684748)
		(width 0.127)
		(layer "In6.Cu")
		(net "ESPI_LPC_LAD0_IO0")
	)
	(segment
		(start 335.899252 -38.465252)
		(end 335.899252 -38.18382)
		(width 0.0889)
		(layer "F.Cu")
		(net "ESPI_LFRAME_N_BMC_CS0_N")
	)
	(segment
		(start 335.73974 -31.293308)
		(end 335.538572 -30.80766)
		(width 0.0889)
		(layer "F.Cu")
		(net "ESPI_LFRAME_N_BMC_CS0_N")
	)
	(segment
		(start 335.73974 -31.776924)
		(end 335.73974 -31.293308)
		(width 0.0889)
		(layer "F.Cu")
		(net "ESPI_LFRAME_N_BMC_CS0_N")
	)
	(segment
		(start 335.899252 -38.18382)
		(end 335.6229 -37.768784)
		(width 0.0889)
		(layer "F.Cu")
		(net "ESPI_LFRAME_N_BMC_CS0_N")
	)
	(segment
		(start 335.144872 -29.023056)
		(end 335.381854 -28.786074)
		(width 0.12954)
		(layer "F.Cu")
		(net "ESPI_LFRAME_N_BMC_CS0_N")
	)
	(segment
		(start 335.538572 -30.80766)
		(end 335.184242 -30.277308)
		(width 0.0889)
		(layer "F.Cu")
		(net "ESPI_LFRAME_N_BMC_CS0_N")
	)
	(segment
		(start 336.018124 -25.470612)
		(end 336.018124 -26.456132)
		(width 0.12954)
		(layer "F.Cu")
		(net "ESPI_LFRAME_N_BMC_CS0_N")
	)
	(segment
		(start 335.144872 -30.182312)
		(end 335.144872 -29.023056)
		(width 0.12954)
		(layer "F.Cu")
		(net "ESPI_LFRAME_N_BMC_CS0_N")
	)
	(segment
		(start 335.6229 -37.768784)
		(end 335.6229 -33.945576)
		(width 0.0889)
		(layer "F.Cu")
		(net "ESPI_LFRAME_N_BMC_CS0_N")
	)
	(segment
		(start 335.6229 -33.945576)
		(end 335.73974 -33.828736)
		(width 0.0889)
		(layer "F.Cu")
		(net "ESPI_LFRAME_N_BMC_CS0_N")
	)
	(segment
		(start 335.184242 -30.277308)
		(end 335.144872 -30.182312)
		(width 0.0889)
		(layer "F.Cu")
		(net "ESPI_LFRAME_N_BMC_CS0_N")
	)
	(segment
		(start 335.381854 -28.786074)
		(end 335.381854 -27.092402)
		(width 0.12954)
		(layer "F.Cu")
		(net "ESPI_LFRAME_N_BMC_CS0_N")
	)
	(segment
		(start 335.73974 -33.828736)
		(end 335.73974 -31.776924)
		(width 0.0889)
		(layer "F.Cu")
		(net "ESPI_LFRAME_N_BMC_CS0_N")
	)
	(segment
		(start 335.381854 -27.092402)
		(end 336.018124 -26.456132)
		(width 0.12954)
		(layer "F.Cu")
		(net "ESPI_LFRAME_N_BMC_CS0_N")
	)
	(via
		(at 335.73974 -31.776924)
		(size 0.762)
		(drill 0.381)
		(layers "F.Cu" "B.Cu")
		(net "ESPI_LFRAME_N_BMC_CS0_N")
	)
	(segment
		(start 335.144872 -37.330634)
		(end 335.144872 -33.73374)
		(width 0.0889)
		(layer "F.Cu")
		(net "ESPI_LAD0_DATA_IO3")
	)
	(segment
		(start 334.178656 -28.112466)
		(end 333.60487 -27.53868)
		(width 0.12954)
		(layer "F.Cu")
		(net "ESPI_LAD0_DATA_IO3")
	)
	(segment
		(start 335.18602 -37.769546)
		(end 335.19491 -37.583364)
		(width 0.0889)
		(layer "F.Cu")
		(net "ESPI_LAD0_DATA_IO3")
	)
	(segment
		(start 333.60487 -27.01925)
		(end 333.986124 -26.637996)
		(width 0.12954)
		(layer "F.Cu")
		(net "ESPI_LAD0_DATA_IO3")
	)
	(segment
		(start 334.9752 -31.494984)
		(end 334.178656 -30.69844)
		(width 0.12954)
		(layer "F.Cu")
		(net "ESPI_LAD0_DATA_IO3")
	)
	(segment
		(start 335.097374 -37.955474)
		(end 335.150714 -37.875972)
		(width 0.0889)
		(layer "F.Cu")
		(net "ESPI_LAD0_DATA_IO3")
	)
	(segment
		(start 335.19491 -37.583364)
		(end 335.144872 -37.330634)
		(width 0.0889)
		(layer "F.Cu")
		(net "ESPI_LAD0_DATA_IO3")
	)
	(segment
		(start 335.399126 -38.880288)
		(end 335.399126 -38.518084)
		(width 0.0889)
		(layer "F.Cu")
		(net "ESPI_LAD0_DATA_IO3")
	)
	(segment
		(start 335.150714 -37.875972)
		(end 335.18602 -37.769546)
		(width 0.0889)
		(layer "F.Cu")
		(net "ESPI_LAD0_DATA_IO3")
	)
	(segment
		(start 333.986124 -26.637996)
		(end 333.986124 -26.356056)
		(width 0.12954)
		(layer "F.Cu")
		(net "ESPI_LAD0_DATA_IO3")
	)
	(segment
		(start 335.097374 -38.196012)
		(end 335.097374 -37.955474)
		(width 0.0889)
		(layer "F.Cu")
		(net "ESPI_LAD0_DATA_IO3")
	)
	(segment
		(start 335.399126 -38.518084)
		(end 335.22666 -38.345618)
		(width 0.0889)
		(layer "F.Cu")
		(net "ESPI_LAD0_DATA_IO3")
	)
	(segment
		(start 333.60487 -27.53868)
		(end 333.60487 -27.01925)
		(width 0.12954)
		(layer "F.Cu")
		(net "ESPI_LAD0_DATA_IO3")
	)
	(segment
		(start 334.9752 -33.564068)
		(end 334.9752 -31.494984)
		(width 0.0889)
		(layer "F.Cu")
		(net "ESPI_LAD0_DATA_IO3")
	)
	(segment
		(start 335.22666 -38.345618)
		(end 335.097374 -38.196012)
		(width 0.0889)
		(layer "F.Cu")
		(net "ESPI_LAD0_DATA_IO3")
	)
	(segment
		(start 334.178656 -30.69844)
		(end 334.178656 -28.112466)
		(width 0.12954)
		(layer "F.Cu")
		(net "ESPI_LAD0_DATA_IO3")
	)
	(segment
		(start 335.144872 -33.73374)
		(end 334.9752 -33.564068)
		(width 0.0889)
		(layer "F.Cu")
		(net "ESPI_LAD0_DATA_IO3")
	)
	(via
		(at 333.60487 -27.53868)
		(size 0.762)
		(drill 0.381)
		(layers "F.Cu" "B.Cu")
		(net "ESPI_LAD0_DATA_IO3")
	)
	(segment
		(start 334.898746 -38.465252)
		(end 334.898746 -38.182804)
		(width 0.0889)
		(layer "F.Cu")
		(net "ESPI_LAD0_DATA_IO2")
	)
	(segment
		(start 334.59166 -37.527992)
		(end 334.658716 -37.300154)
		(width 0.0889)
		(layer "F.Cu")
		(net "ESPI_LAD0_DATA_IO2")
	)
	(segment
		(start 333.75727 -29.63164)
		(end 333.449168 -28.887928)
		(width 0.12954)
		(layer "F.Cu")
		(net "ESPI_LAD0_DATA_IO2")
	)
	(segment
		(start 333.449168 -28.887928)
		(end 333.449168 -28.438602)
		(width 0.12954)
		(layer "F.Cu")
		(net "ESPI_LAD0_DATA_IO2")
	)
	(segment
		(start 334.59166 -37.723572)
		(end 334.59166 -37.527992)
		(width 0.0889)
		(layer "F.Cu")
		(net "ESPI_LAD0_DATA_IO2")
	)
	(segment
		(start 334.658716 -34.085784)
		(end 334.186784 -33.613852)
		(width 0.0889)
		(layer "F.Cu")
		(net "ESPI_LAD0_DATA_IO2")
	)
	(segment
		(start 333.77251 -31.26613)
		(end 333.77251 -29.64688)
		(width 0.12954)
		(layer "F.Cu")
		(net "ESPI_LAD0_DATA_IO2")
	)
	(segment
		(start 333.449168 -28.438602)
		(end 332.970124 -27.959558)
		(width 0.12954)
		(layer "F.Cu")
		(net "ESPI_LAD0_DATA_IO2")
	)
	(segment
		(start 333.661258 -33.613852)
		(end 333.397352 -33.349946)
		(width 0.0889)
		(layer "F.Cu")
		(net "ESPI_LAD0_DATA_IO2")
	)
	(segment
		(start 332.970124 -27.959558)
		(end 332.970124 -26.356056)
		(width 0.12954)
		(layer "F.Cu")
		(net "ESPI_LAD0_DATA_IO2")
	)
	(segment
		(start 334.658716 -37.300154)
		(end 334.658716 -34.085784)
		(width 0.0889)
		(layer "F.Cu")
		(net "ESPI_LAD0_DATA_IO2")
	)
	(segment
		(start 333.397352 -32.418528)
		(end 333.77251 -32.04337)
		(width 0.0889)
		(layer "F.Cu")
		(net "ESPI_LAD0_DATA_IO2")
	)
	(segment
		(start 333.77251 -32.04337)
		(end 333.77251 -31.26613)
		(width 0.0889)
		(layer "F.Cu")
		(net "ESPI_LAD0_DATA_IO2")
	)
	(segment
		(start 333.77251 -29.64688)
		(end 333.75727 -29.63164)
		(width 0.12954)
		(layer "F.Cu")
		(net "ESPI_LAD0_DATA_IO2")
	)
	(segment
		(start 334.186784 -33.613852)
		(end 333.661258 -33.613852)
		(width 0.0889)
		(layer "F.Cu")
		(net "ESPI_LAD0_DATA_IO2")
	)
	(segment
		(start 333.397352 -33.349946)
		(end 333.397352 -32.418528)
		(width 0.0889)
		(layer "F.Cu")
		(net "ESPI_LAD0_DATA_IO2")
	)
	(segment
		(start 334.898746 -38.182804)
		(end 334.59166 -37.723572)
		(width 0.0889)
		(layer "F.Cu")
		(net "ESPI_LAD0_DATA_IO2")
	)
	(via
		(at 333.449168 -28.887928)
		(size 0.762)
		(drill 0.381)
		(layers "F.Cu" "B.Cu")
		(net "ESPI_LAD0_DATA_IO2")
	)
	(segment
		(start 334.809084 -26.859992)
		(end 335.002124 -26.666952)
		(width 0.12954)
		(layer "F.Cu")
		(net "ESPI_LAD0_DATA_IO1")
	)
	(segment
		(start 335.202276 -33.119314)
		(end 335.202276 -31.184088)
		(width 0.0889)
		(layer "F.Cu")
		(net "ESPI_LAD0_DATA_IO1")
	)
	(segment
		(start 335.202276 -31.184088)
		(end 334.653636 -30.635448)
		(width 0.12954)
		(layer "F.Cu")
		(net "ESPI_LAD0_DATA_IO1")
	)
	(segment
		(start 334.653636 -30.635448)
		(end 334.653636 -28.774136)
		(width 0.12954)
		(layer "F.Cu")
		(net "ESPI_LAD0_DATA_IO1")
	)
	(segment
		(start 335.399126 -33.316164)
		(end 335.202276 -33.119314)
		(width 0.0889)
		(layer "F.Cu")
		(net "ESPI_LAD0_DATA_IO1")
	)
	(segment
		(start 335.399126 -38.050216)
		(end 335.399126 -33.316164)
		(width 0.0889)
		(layer "F.Cu")
		(net "ESPI_LAD0_DATA_IO1")
	)
	(segment
		(start 334.809084 -28.174696)
		(end 334.809084 -26.859992)
		(width 0.12954)
		(layer "F.Cu")
		(net "ESPI_LAD0_DATA_IO1")
	)
	(segment
		(start 335.002124 -26.666952)
		(end 335.002124 -26.354532)
		(width 0.12954)
		(layer "F.Cu")
		(net "ESPI_LAD0_DATA_IO1")
	)
	(segment
		(start 334.653636 -28.774136)
		(end 334.809084 -28.618688)
		(width 0.12954)
		(layer "F.Cu")
		(net "ESPI_LAD0_DATA_IO1")
	)
	(segment
		(start 334.809084 -28.618688)
		(end 334.809084 -28.174696)
		(width 0.12954)
		(layer "F.Cu")
		(net "ESPI_LAD0_DATA_IO1")
	)
	(via
		(at 334.809084 -28.174696)
		(size 0.762)
		(drill 0.381)
		(layers "F.Cu" "B.Cu")
		(net "ESPI_LAD0_DATA_IO1")
	)
	(segment
		(start 329.248262 -25.412446)
		(end 329.248262 -28.240228)
		(width 0.12954)
		(layer "F.Cu")
		(net "ESPI_LAD0_DATA_IO0")
	)
	(segment
		(start 329.124818 -25.07234)
		(end 329.124818 -24.203914)
		(width 0.12954)
		(layer "F.Cu")
		(net "ESPI_LAD0_DATA_IO0")
	)
	(segment
		(start 330.939394 -33.49752)
		(end 330.939394 -34.32302)
		(width 0.0889)
		(layer "F.Cu")
		(net "ESPI_LAD0_DATA_IO0")
	)
	(segment
		(start 329.248262 -25.412446)
		(end 329.248262 -25.195784)
		(width 0.12954)
		(layer "F.Cu")
		(net "ESPI_LAD0_DATA_IO0")
	)
	(segment
		(start 331.897228 -35.280854)
		(end 331.897228 -37.634926)
		(width 0.0889)
		(layer "F.Cu")
		(net "ESPI_LAD0_DATA_IO0")
	)
	(segment
		(start 329.248262 -28.240228)
		(end 328.851514 -29.198316)
		(width 0.12954)
		(layer "F.Cu")
		(net "ESPI_LAD0_DATA_IO0")
	)
	(segment
		(start 330.24826 -32.19196)
		(end 330.24826 -32.806386)
		(width 0.0889)
		(layer "F.Cu")
		(net "ESPI_LAD0_DATA_IO0")
	)
	(segment
		(start 328.851514 -29.198316)
		(end 328.851514 -29.750766)
		(width 0.12954)
		(layer "F.Cu")
		(net "ESPI_LAD0_DATA_IO0")
	)
	(segment
		(start 328.851514 -29.750766)
		(end 329.282552 -30.792166)
		(width 0.0889)
		(layer "F.Cu")
		(net "ESPI_LAD0_DATA_IO0")
	)
	(segment
		(start 330.939394 -34.32302)
		(end 331.897228 -35.280854)
		(width 0.0889)
		(layer "F.Cu")
		(net "ESPI_LAD0_DATA_IO0")
	)
	(segment
		(start 330.24826 -32.806386)
		(end 330.939394 -33.49752)
		(width 0.0889)
		(layer "F.Cu")
		(net "ESPI_LAD0_DATA_IO0")
	)
	(segment
		(start 331.897228 -37.634926)
		(end 331.897482 -37.63518)
		(width 0.0889)
		(layer "F.Cu")
		(net "ESPI_LAD0_DATA_IO0")
	)
	(segment
		(start 329.282552 -30.792166)
		(end 329.941428 -31.451042)
		(width 0.0889)
		(layer "F.Cu")
		(net "ESPI_LAD0_DATA_IO0")
	)
	(segment
		(start 329.248262 -25.195784)
		(end 329.124818 -25.07234)
		(width 0.12954)
		(layer "F.Cu")
		(net "ESPI_LAD0_DATA_IO0")
	)
	(segment
		(start 329.941428 -31.451042)
		(end 330.24826 -32.19196)
		(width 0.0889)
		(layer "F.Cu")
		(net "ESPI_LAD0_DATA_IO0")
	)
	(via
		(at 329.248262 -25.412446)
		(size 0.762)
		(drill 0.381)
		(layers "F.Cu" "B.Cu")
		(net "ESPI_LAD0_DATA_IO0")
	)
	(segment
		(start 178.1556 -17.870424)
		(end 178.266852 -17.759172)
		(width 0.12954)
		(layer "F.Cu")
		(net "ESPI_HOST_LPC_BMC_LFRAME_N")
	)
	(segment
		(start 178.266852 -17.466056)
		(end 178.267106 -17.465802)
		(width 0.12954)
		(layer "F.Cu")
		(net "ESPI_HOST_LPC_BMC_LFRAME_N")
	)
	(segment
		(start 178.267106 -17.465802)
		(end 178.267106 -16.550132)
		(width 0.12954)
		(layer "F.Cu")
		(net "ESPI_HOST_LPC_BMC_LFRAME_N")
	)
	(segment
		(start 336.018124 -24.670512)
		(end 336.018124 -23.929848)
		(width 0.12954)
		(layer "F.Cu")
		(net "ESPI_HOST_LPC_BMC_LFRAME_N")
	)
	(segment
		(start 178.1556 -18.316448)
		(end 178.1556 -17.870424)
		(width 0.12954)
		(layer "F.Cu")
		(net "ESPI_HOST_LPC_BMC_LFRAME_N")
	)
	(segment
		(start 178.266852 -17.759172)
		(end 178.266852 -17.466056)
		(width 0.12954)
		(layer "F.Cu")
		(net "ESPI_HOST_LPC_BMC_LFRAME_N")
	)
	(via
		(at 178.1556 -18.316448)
		(size 0.508)
		(drill 0.254)
		(layers "F.Cu" "B.Cu")
		(net "ESPI_HOST_LPC_BMC_LFRAME_N")
	)
	(via
		(at 336.018124 -23.929848)
		(size 0.508)
		(drill 0.254)
		(layers "F.Cu" "B.Cu")
		(net "ESPI_HOST_LPC_BMC_LFRAME_N")
	)
	(segment
		(start 193.787522 -26.290778)
		(end 194.835272 -28.820364)
		(width 0.127)
		(layer "In6.Cu")
		(net "ESPI_HOST_LPC_BMC_LFRAME_N")
	)
	(segment
		(start 322.75907 -23.735538)
		(end 325.02729 -23.735538)
		(width 0.127)
		(layer "In6.Cu")
		(net "ESPI_HOST_LPC_BMC_LFRAME_N")
	)
	(segment
		(start 333.65948 -20.589748)
		(end 336.018124 -22.948392)
		(width 0.127)
		(layer "In6.Cu")
		(net "ESPI_HOST_LPC_BMC_LFRAME_N")
	)
	(segment
		(start 329.16368 -23.713948)
		(end 329.16368 -23.720044)
		(width 0.127)
		(layer "In6.Cu")
		(net "ESPI_HOST_LPC_BMC_LFRAME_N")
	)
	(segment
		(start 178.562 -18.97888)
		(end 178.562 -19.199352)
		(width 0.127)
		(layer "In6.Cu")
		(net "ESPI_HOST_LPC_BMC_LFRAME_N")
	)
	(segment
		(start 218.14663 -39.388542)
		(end 218.14663 -49.376076)
		(width 0.127)
		(layer "In6.Cu")
		(net "ESPI_HOST_LPC_BMC_LFRAME_N")
	)
	(segment
		(start 259.374386 -62.550548)
		(end 261.913878 -61.498734)
		(width 0.127)
		(layer "In6.Cu")
		(net "ESPI_HOST_LPC_BMC_LFRAME_N")
	)
	(segment
		(start 261.913878 -61.498734)
		(end 265.129264 -58.283348)
		(width 0.127)
		(layer "In6.Cu")
		(net "ESPI_HOST_LPC_BMC_LFRAME_N")
	)
	(segment
		(start 332.54188 -20.869148)
		(end 332.82128 -20.589748)
		(width 0.127)
		(layer "In6.Cu")
		(net "ESPI_HOST_LPC_BMC_LFRAME_N")
	)
	(segment
		(start 211.402676 -32.644588)
		(end 218.14663 -39.388542)
		(width 0.127)
		(layer "In6.Cu")
		(net "ESPI_HOST_LPC_BMC_LFRAME_N")
	)
	(segment
		(start 325.02729 -23.735538)
		(end 325.83628 -22.926548)
		(width 0.127)
		(layer "In6.Cu")
		(net "ESPI_HOST_LPC_BMC_LFRAME_N")
	)
	(segment
		(start 329.16368 -23.720044)
		(end 330.173584 -24.729948)
		(width 0.127)
		(layer "In6.Cu")
		(net "ESPI_HOST_LPC_BMC_LFRAME_N")
	)
	(segment
		(start 194.835272 -28.820364)
		(end 198.659496 -32.644588)
		(width 0.127)
		(layer "In6.Cu")
		(net "ESPI_HOST_LPC_BMC_LFRAME_N")
	)
	(segment
		(start 336.018124 -22.948392)
		(end 336.018124 -23.929848)
		(width 0.127)
		(layer "In6.Cu")
		(net "ESPI_HOST_LPC_BMC_LFRAME_N")
	)
	(segment
		(start 330.61148 -24.729948)
		(end 332.54188 -22.799548)
		(width 0.127)
		(layer "In6.Cu")
		(net "ESPI_HOST_LPC_BMC_LFRAME_N")
	)
	(segment
		(start 320.907156 -23.053548)
		(end 322.07708 -23.053548)
		(width 0.127)
		(layer "In6.Cu")
		(net "ESPI_HOST_LPC_BMC_LFRAME_N")
	)
	(segment
		(start 178.1556 -18.57248)
		(end 178.562 -18.97888)
		(width 0.127)
		(layer "In6.Cu")
		(net "ESPI_HOST_LPC_BMC_LFRAME_N")
	)
	(segment
		(start 318.62649 -25.334214)
		(end 320.907156 -23.053548)
		(width 0.127)
		(layer "In6.Cu")
		(net "ESPI_HOST_LPC_BMC_LFRAME_N")
	)
	(segment
		(start 328.37628 -22.926548)
		(end 329.16368 -23.713948)
		(width 0.127)
		(layer "In6.Cu")
		(net "ESPI_HOST_LPC_BMC_LFRAME_N")
	)
	(segment
		(start 183.93156 -20.737068)
		(end 184.65038 -20.018248)
		(width 0.127)
		(layer "In6.Cu")
		(net "ESPI_HOST_LPC_BMC_LFRAME_N")
	)
	(segment
		(start 330.173584 -24.729948)
		(end 330.61148 -24.729948)
		(width 0.127)
		(layer "In6.Cu")
		(net "ESPI_HOST_LPC_BMC_LFRAME_N")
	)
	(segment
		(start 332.54188 -22.799548)
		(end 332.54188 -20.869148)
		(width 0.127)
		(layer "In6.Cu")
		(net "ESPI_HOST_LPC_BMC_LFRAME_N")
	)
	(segment
		(start 332.82128 -20.589748)
		(end 333.65948 -20.589748)
		(width 0.127)
		(layer "In6.Cu")
		(net "ESPI_HOST_LPC_BMC_LFRAME_N")
	)
	(segment
		(start 198.659496 -32.644588)
		(end 211.402676 -32.644588)
		(width 0.127)
		(layer "In6.Cu")
		(net "ESPI_HOST_LPC_BMC_LFRAME_N")
	)
	(segment
		(start 190.821564 -20.018248)
		(end 193.787522 -22.984206)
		(width 0.127)
		(layer "In6.Cu")
		(net "ESPI_HOST_LPC_BMC_LFRAME_N")
	)
	(segment
		(start 182.00624 -20.737068)
		(end 183.93156 -20.737068)
		(width 0.127)
		(layer "In6.Cu")
		(net "ESPI_HOST_LPC_BMC_LFRAME_N")
	)
	(segment
		(start 241.13617 -63.917068)
		(end 242.50269 -62.550548)
		(width 0.127)
		(layer "In6.Cu")
		(net "ESPI_HOST_LPC_BMC_LFRAME_N")
	)
	(segment
		(start 265.129264 -58.283348)
		(end 271.93748 -58.283348)
		(width 0.127)
		(layer "In6.Cu")
		(net "ESPI_HOST_LPC_BMC_LFRAME_N")
	)
	(segment
		(start 296.180256 -34.040572)
		(end 296.180256 -32.718756)
		(width 0.127)
		(layer "In6.Cu")
		(net "ESPI_HOST_LPC_BMC_LFRAME_N")
	)
	(segment
		(start 193.787522 -22.984206)
		(end 193.787522 -26.290778)
		(width 0.127)
		(layer "In6.Cu")
		(net "ESPI_HOST_LPC_BMC_LFRAME_N")
	)
	(segment
		(start 178.1556 -18.316448)
		(end 178.1556 -18.57248)
		(width 0.127)
		(layer "In6.Cu")
		(net "ESPI_HOST_LPC_BMC_LFRAME_N")
	)
	(segment
		(start 303.564798 -25.334214)
		(end 318.62649 -25.334214)
		(width 0.127)
		(layer "In6.Cu")
		(net "ESPI_HOST_LPC_BMC_LFRAME_N")
	)
	(segment
		(start 178.562 -19.199352)
		(end 180.579776 -21.217128)
		(width 0.127)
		(layer "In6.Cu")
		(net "ESPI_HOST_LPC_BMC_LFRAME_N")
	)
	(segment
		(start 296.180256 -32.718756)
		(end 303.564798 -25.334214)
		(width 0.127)
		(layer "In6.Cu")
		(net "ESPI_HOST_LPC_BMC_LFRAME_N")
	)
	(segment
		(start 180.579776 -21.217128)
		(end 181.52618 -21.217128)
		(width 0.127)
		(layer "In6.Cu")
		(net "ESPI_HOST_LPC_BMC_LFRAME_N")
	)
	(segment
		(start 242.50269 -62.550548)
		(end 259.374386 -62.550548)
		(width 0.127)
		(layer "In6.Cu")
		(net "ESPI_HOST_LPC_BMC_LFRAME_N")
	)
	(segment
		(start 232.687622 -63.917068)
		(end 241.13617 -63.917068)
		(width 0.127)
		(layer "In6.Cu")
		(net "ESPI_HOST_LPC_BMC_LFRAME_N")
	)
	(segment
		(start 218.14663 -49.376076)
		(end 232.687622 -63.917068)
		(width 0.127)
		(layer "In6.Cu")
		(net "ESPI_HOST_LPC_BMC_LFRAME_N")
	)
	(segment
		(start 271.93748 -58.283348)
		(end 296.180256 -34.040572)
		(width 0.127)
		(layer "In6.Cu")
		(net "ESPI_HOST_LPC_BMC_LFRAME_N")
	)
	(segment
		(start 325.83628 -22.926548)
		(end 328.37628 -22.926548)
		(width 0.127)
		(layer "In6.Cu")
		(net "ESPI_HOST_LPC_BMC_LFRAME_N")
	)
	(segment
		(start 181.52618 -21.217128)
		(end 182.00624 -20.737068)
		(width 0.127)
		(layer "In6.Cu")
		(net "ESPI_HOST_LPC_BMC_LFRAME_N")
	)
	(segment
		(start 322.07708 -23.053548)
		(end 322.75907 -23.735538)
		(width 0.127)
		(layer "In6.Cu")
		(net "ESPI_HOST_LPC_BMC_LFRAME_N")
	)
	(segment
		(start 184.65038 -20.018248)
		(end 190.821564 -20.018248)
		(width 0.127)
		(layer "In6.Cu")
		(net "ESPI_HOST_LPC_BMC_LFRAME_N")
	)
	(segment
		(start 178.867054 -17.465802)
		(end 178.8668 -17.466056)
		(width 0.12954)
		(layer "F.Cu")
		(net "ESPI_HOST_LPC_BMC_CLK")
	)
	(segment
		(start 329.795378 -26.43505)
		(end 329.795378 -26.642568)
		(width 0.12954)
		(layer "F.Cu")
		(net "ESPI_HOST_LPC_BMC_CLK")
	)
	(segment
		(start 178.867054 -16.550132)
		(end 178.867054 -17.465802)
		(width 0.12954)
		(layer "F.Cu")
		(net "ESPI_HOST_LPC_BMC_CLK")
	)
	(segment
		(start 329.84948 -24.933148)
		(end 329.84948 -26.380948)
		(width 0.12954)
		(layer "F.Cu")
		(net "ESPI_HOST_LPC_BMC_CLK")
	)
	(segment
		(start 329.74788 -23.744428)
		(end 329.74788 -24.831548)
		(width 0.12954)
		(layer "F.Cu")
		(net "ESPI_HOST_LPC_BMC_CLK")
	)
	(segment
		(start 178.8668 -17.794224)
		(end 178.7906 -17.870424)
		(width 0.12954)
		(layer "F.Cu")
		(net "ESPI_HOST_LPC_BMC_CLK")
	)
	(segment
		(start 178.7906 -17.870424)
		(end 178.7906 -18.316448)
		(width 0.12954)
		(layer "F.Cu")
		(net "ESPI_HOST_LPC_BMC_CLK")
	)
	(segment
		(start 178.8668 -17.466056)
		(end 178.8668 -17.794224)
		(width 0.12954)
		(layer "F.Cu")
		(net "ESPI_HOST_LPC_BMC_CLK")
	)
	(segment
		(start 329.85456 -23.637748)
		(end 329.74788 -23.744428)
		(width 0.12954)
		(layer "F.Cu")
		(net "ESPI_HOST_LPC_BMC_CLK")
	)
	(segment
		(start 329.74788 -24.831548)
		(end 329.84948 -24.933148)
		(width 0.12954)
		(layer "F.Cu")
		(net "ESPI_HOST_LPC_BMC_CLK")
	)
	(segment
		(start 329.84948 -26.380948)
		(end 329.795378 -26.43505)
		(width 0.12954)
		(layer "F.Cu")
		(net "ESPI_HOST_LPC_BMC_CLK")
	)
	(via
		(at 329.85456 -23.637748)
		(size 0.508)
		(drill 0.254)
		(layers "F.Cu" "B.Cu")
		(net "ESPI_HOST_LPC_BMC_CLK")
	)
	(via
		(at 178.7906 -18.316448)
		(size 0.508)
		(drill 0.254)
		(layers "F.Cu" "B.Cu")
		(net "ESPI_HOST_LPC_BMC_CLK")
	)
	(segment
		(start 288.98215 -39.359078)
		(end 289.161982 -39.359078)
		(width 0.127)
		(layer "In6.Cu")
		(net "ESPI_HOST_LPC_BMC_CLK")
	)
	(segment
		(start 287.536382 -40.984678)
		(end 287.536382 -40.804846)
		(width 0.127)
		(layer "In6.Cu")
		(net "ESPI_HOST_LPC_BMC_CLK")
	)
	(segment
		(start 289.21583 -40.063166)
		(end 288.836862 -39.684198)
		(width 0.127)
		(layer "In6.Cu")
		(net "ESPI_HOST_LPC_BMC_CLK")
	)
	(segment
		(start 242.313206 -62.093348)
		(end 259.2832 -62.093348)
		(width 0.127)
		(layer "In6.Cu")
		(net "ESPI_HOST_LPC_BMC_CLK")
	)
	(segment
		(start 303.403254 -24.849074)
		(end 317.881762 -24.849074)
		(width 0.127)
		(layer "In6.Cu")
		(net "ESPI_HOST_LPC_BMC_CLK")
	)
	(segment
		(start 290.19119 -39.087806)
		(end 290.371022 -39.087806)
		(width 0.127)
		(layer "In6.Cu")
		(net "ESPI_HOST_LPC_BMC_CLK")
	)
	(segment
		(start 183.7309 -20.277328)
		(end 184.44718 -19.561048)
		(width 0.127)
		(layer "In6.Cu")
		(net "ESPI_HOST_LPC_BMC_CLK")
	)
	(segment
		(start 287.536382 -40.804846)
		(end 287.68167 -40.659558)
		(width 0.127)
		(layer "In6.Cu")
		(net "ESPI_HOST_LPC_BMC_CLK")
	)
	(segment
		(start 287.211262 -41.309798)
		(end 287.59023 -41.688766)
		(width 0.127)
		(layer "In6.Cu")
		(net "ESPI_HOST_LPC_BMC_CLK")
	)
	(segment
		(start 287.91535 -41.363646)
		(end 287.536382 -40.984678)
		(width 0.127)
		(layer "In6.Cu")
		(net "ESPI_HOST_LPC_BMC_CLK")
	)
	(segment
		(start 289.487102 -39.033958)
		(end 289.487102 -38.854126)
		(width 0.127)
		(layer "In6.Cu")
		(net "ESPI_HOST_LPC_BMC_CLK")
	)
	(segment
		(start 295.723056 -33.735772)
		(end 295.723056 -32.529272)
		(width 0.127)
		(layer "In6.Cu")
		(net "ESPI_HOST_LPC_BMC_CLK")
	)
	(segment
		(start 289.86607 -39.412926)
		(end 289.487102 -39.033958)
		(width 0.127)
		(layer "In6.Cu")
		(net "ESPI_HOST_LPC_BMC_CLK")
	)
	(segment
		(start 288.24047 -41.038526)
		(end 288.420302 -41.038526)
		(width 0.127)
		(layer "In6.Cu")
		(net "ESPI_HOST_LPC_BMC_CLK")
	)
	(segment
		(start 288.56559 -40.893238)
		(end 288.56559 -40.713406)
		(width 0.127)
		(layer "In6.Cu")
		(net "ESPI_HOST_LPC_BMC_CLK")
	)
	(segment
		(start 320.925698 -21.805138)
		(end 328.02195 -21.805138)
		(width 0.127)
		(layer "In6.Cu")
		(net "ESPI_HOST_LPC_BMC_CLK")
	)
	(segment
		(start 184.44718 -19.561048)
		(end 191.011048 -19.561048)
		(width 0.127)
		(layer "In6.Cu")
		(net "ESPI_HOST_LPC_BMC_CLK")
	)
	(segment
		(start 179.07 -19.060668)
		(end 180.76926 -20.759928)
		(width 0.127)
		(layer "In6.Cu")
		(net "ESPI_HOST_LPC_BMC_CLK")
	)
	(segment
		(start 289.720782 -39.738046)
		(end 289.86607 -39.592758)
		(width 0.127)
		(layer "In6.Cu")
		(net "ESPI_HOST_LPC_BMC_CLK")
	)
	(segment
		(start 289.070542 -40.388286)
		(end 289.21583 -40.242998)
		(width 0.127)
		(layer "In6.Cu")
		(net "ESPI_HOST_LPC_BMC_CLK")
	)
	(segment
		(start 271.70888 -57.749948)
		(end 287.26511 -42.193718)
		(width 0.127)
		(layer "In6.Cu")
		(net "ESPI_HOST_LPC_BMC_CLK")
	)
	(segment
		(start 287.59023 -41.688766)
		(end 287.770062 -41.688766)
		(width 0.127)
		(layer "In6.Cu")
		(net "ESPI_HOST_LPC_BMC_CLK")
	)
	(segment
		(start 287.03143 -41.309798)
		(end 287.211262 -41.309798)
		(width 0.127)
		(layer "In6.Cu")
		(net "ESPI_HOST_LPC_BMC_CLK")
	)
	(segment
		(start 317.881762 -24.849074)
		(end 320.925698 -21.805138)
		(width 0.127)
		(layer "In6.Cu")
		(net "ESPI_HOST_LPC_BMC_CLK")
	)
	(segment
		(start 289.54095 -39.738046)
		(end 289.720782 -39.738046)
		(width 0.127)
		(layer "In6.Cu")
		(net "ESPI_HOST_LPC_BMC_CLK")
	)
	(segment
		(start 240.946686 -63.459868)
		(end 242.313206 -62.093348)
		(width 0.127)
		(layer "In6.Cu")
		(net "ESPI_HOST_LPC_BMC_CLK")
	)
	(segment
		(start 211.59216 -32.187388)
		(end 218.60383 -39.199058)
		(width 0.127)
		(layer "In6.Cu")
		(net "ESPI_HOST_LPC_BMC_CLK")
	)
	(segment
		(start 288.836862 -39.684198)
		(end 288.836862 -39.504366)
		(width 0.127)
		(layer "In6.Cu")
		(net "ESPI_HOST_LPC_BMC_CLK")
	)
	(segment
		(start 287.26511 -42.013886)
		(end 286.886142 -41.634918)
		(width 0.127)
		(layer "In6.Cu")
		(net "ESPI_HOST_LPC_BMC_CLK")
	)
	(segment
		(start 288.186622 -40.154606)
		(end 288.33191 -40.009318)
		(width 0.127)
		(layer "In6.Cu")
		(net "ESPI_HOST_LPC_BMC_CLK")
	)
	(segment
		(start 328.02195 -21.805138)
		(end 329.85456 -23.637748)
		(width 0.127)
		(layer "In6.Cu")
		(net "ESPI_HOST_LPC_BMC_CLK")
	)
	(segment
		(start 195.22313 -28.561538)
		(end 198.84898 -32.187388)
		(width 0.127)
		(layer "In6.Cu")
		(net "ESPI_HOST_LPC_BMC_CLK")
	)
	(segment
		(start 287.861502 -40.659558)
		(end 288.24047 -41.038526)
		(width 0.127)
		(layer "In6.Cu")
		(net "ESPI_HOST_LPC_BMC_CLK")
	)
	(segment
		(start 287.770062 -41.688766)
		(end 287.91535 -41.543478)
		(width 0.127)
		(layer "In6.Cu")
		(net "ESPI_HOST_LPC_BMC_CLK")
	)
	(segment
		(start 179.07 -18.99158)
		(end 179.07 -19.060668)
		(width 0.127)
		(layer "In6.Cu")
		(net "ESPI_HOST_LPC_BMC_CLK")
	)
	(segment
		(start 261.646162 -61.114686)
		(end 265.0109 -57.749948)
		(width 0.127)
		(layer "In6.Cu")
		(net "ESPI_HOST_LPC_BMC_CLK")
	)
	(segment
		(start 198.84898 -32.187388)
		(end 211.59216 -32.187388)
		(width 0.127)
		(layer "In6.Cu")
		(net "ESPI_HOST_LPC_BMC_CLK")
	)
	(segment
		(start 218.60383 -39.199058)
		(end 218.60383 -49.186592)
		(width 0.127)
		(layer "In6.Cu")
		(net "ESPI_HOST_LPC_BMC_CLK")
	)
	(segment
		(start 288.511742 -40.009318)
		(end 288.89071 -40.388286)
		(width 0.127)
		(layer "In6.Cu")
		(net "ESPI_HOST_LPC_BMC_CLK")
	)
	(segment
		(start 288.89071 -40.388286)
		(end 289.070542 -40.388286)
		(width 0.127)
		(layer "In6.Cu")
		(net "ESPI_HOST_LPC_BMC_CLK")
	)
	(segment
		(start 287.26511 -42.193718)
		(end 287.26511 -42.013886)
		(width 0.127)
		(layer "In6.Cu")
		(net "ESPI_HOST_LPC_BMC_CLK")
	)
	(segment
		(start 295.723056 -32.529272)
		(end 303.403254 -24.849074)
		(width 0.127)
		(layer "In6.Cu")
		(net "ESPI_HOST_LPC_BMC_CLK")
	)
	(segment
		(start 232.877106 -63.459868)
		(end 240.946686 -63.459868)
		(width 0.127)
		(layer "In6.Cu")
		(net "ESPI_HOST_LPC_BMC_CLK")
	)
	(segment
		(start 194.244722 -22.794722)
		(end 194.244722 -26.199592)
		(width 0.127)
		(layer "In6.Cu")
		(net "ESPI_HOST_LPC_BMC_CLK")
	)
	(segment
		(start 181.81066 -20.277328)
		(end 183.7309 -20.277328)
		(width 0.127)
		(layer "In6.Cu")
		(net "ESPI_HOST_LPC_BMC_CLK")
	)
	(segment
		(start 286.886142 -41.634918)
		(end 286.886142 -41.455086)
		(width 0.127)
		(layer "In6.Cu")
		(net "ESPI_HOST_LPC_BMC_CLK")
	)
	(segment
		(start 265.0109 -57.749948)
		(end 271.70888 -57.749948)
		(width 0.127)
		(layer "In6.Cu")
		(net "ESPI_HOST_LPC_BMC_CLK")
	)
	(segment
		(start 286.886142 -41.455086)
		(end 287.03143 -41.309798)
		(width 0.127)
		(layer "In6.Cu")
		(net "ESPI_HOST_LPC_BMC_CLK")
	)
	(segment
		(start 287.68167 -40.659558)
		(end 287.861502 -40.659558)
		(width 0.127)
		(layer "In6.Cu")
		(net "ESPI_HOST_LPC_BMC_CLK")
	)
	(segment
		(start 288.33191 -40.009318)
		(end 288.511742 -40.009318)
		(width 0.127)
		(layer "In6.Cu")
		(net "ESPI_HOST_LPC_BMC_CLK")
	)
	(segment
		(start 288.420302 -41.038526)
		(end 288.56559 -40.893238)
		(width 0.127)
		(layer "In6.Cu")
		(net "ESPI_HOST_LPC_BMC_CLK")
	)
	(segment
		(start 218.60383 -49.186592)
		(end 232.877106 -63.459868)
		(width 0.127)
		(layer "In6.Cu")
		(net "ESPI_HOST_LPC_BMC_CLK")
	)
	(segment
		(start 289.487102 -38.854126)
		(end 289.63239 -38.708838)
		(width 0.127)
		(layer "In6.Cu")
		(net "ESPI_HOST_LPC_BMC_CLK")
	)
	(segment
		(start 288.836862 -39.504366)
		(end 288.98215 -39.359078)
		(width 0.127)
		(layer "In6.Cu")
		(net "ESPI_HOST_LPC_BMC_CLK")
	)
	(segment
		(start 180.76926 -20.759928)
		(end 181.32806 -20.759928)
		(width 0.127)
		(layer "In6.Cu")
		(net "ESPI_HOST_LPC_BMC_CLK")
	)
	(segment
		(start 288.56559 -40.713406)
		(end 288.186622 -40.334438)
		(width 0.127)
		(layer "In6.Cu")
		(net "ESPI_HOST_LPC_BMC_CLK")
	)
	(segment
		(start 290.371022 -39.087806)
		(end 295.723056 -33.735772)
		(width 0.127)
		(layer "In6.Cu")
		(net "ESPI_HOST_LPC_BMC_CLK")
	)
	(segment
		(start 289.63239 -38.708838)
		(end 289.812222 -38.708838)
		(width 0.127)
		(layer "In6.Cu")
		(net "ESPI_HOST_LPC_BMC_CLK")
	)
	(segment
		(start 289.86607 -39.592758)
		(end 289.86607 -39.412926)
		(width 0.127)
		(layer "In6.Cu")
		(net "ESPI_HOST_LPC_BMC_CLK")
	)
	(segment
		(start 288.186622 -40.334438)
		(end 288.186622 -40.154606)
		(width 0.127)
		(layer "In6.Cu")
		(net "ESPI_HOST_LPC_BMC_CLK")
	)
	(segment
		(start 289.812222 -38.708838)
		(end 290.19119 -39.087806)
		(width 0.127)
		(layer "In6.Cu")
		(net "ESPI_HOST_LPC_BMC_CLK")
	)
	(segment
		(start 194.244722 -26.199592)
		(end 195.22313 -28.561538)
		(width 0.127)
		(layer "In6.Cu")
		(net "ESPI_HOST_LPC_BMC_CLK")
	)
	(segment
		(start 259.2832 -62.093348)
		(end 261.646162 -61.114686)
		(width 0.127)
		(layer "In6.Cu")
		(net "ESPI_HOST_LPC_BMC_CLK")
	)
	(segment
		(start 181.32806 -20.759928)
		(end 181.81066 -20.277328)
		(width 0.127)
		(layer "In6.Cu")
		(net "ESPI_HOST_LPC_BMC_CLK")
	)
	(segment
		(start 287.91535 -41.543478)
		(end 287.91535 -41.363646)
		(width 0.127)
		(layer "In6.Cu")
		(net "ESPI_HOST_LPC_BMC_CLK")
	)
	(segment
		(start 191.011048 -19.561048)
		(end 194.244722 -22.794722)
		(width 0.127)
		(layer "In6.Cu")
		(net "ESPI_HOST_LPC_BMC_CLK")
	)
	(segment
		(start 289.161982 -39.359078)
		(end 289.54095 -39.738046)
		(width 0.127)
		(layer "In6.Cu")
		(net "ESPI_HOST_LPC_BMC_CLK")
	)
	(segment
		(start 178.7906 -18.316448)
		(end 179.07 -18.99158)
		(width 0.127)
		(layer "In6.Cu")
		(net "ESPI_HOST_LPC_BMC_CLK")
	)
	(segment
		(start 289.21583 -40.242998)
		(end 289.21583 -40.063166)
		(width 0.127)
		(layer "In6.Cu")
		(net "ESPI_HOST_LPC_BMC_CLK")
	)
	(segment
		(start 176.9618 -17.570958)
		(end 176.9618 -18.405348)
		(width 0.12954)
		(layer "F.Cu")
		(net "ESPI_BMC_LPC_RST_N")
	)
	(segment
		(start 177.066956 -16.550132)
		(end 177.066956 -17.465802)
		(width 0.12954)
		(layer "F.Cu")
		(net "ESPI_BMC_LPC_RST_N")
	)
	(segment
		(start 333.542386 -20.607782)
		(end 333.735426 -20.607782)
		(width 0.12954)
		(layer "F.Cu")
		(net "ESPI_BMC_LPC_RST_N")
	)
	(segment
		(start 333.06004 -21.090128)
		(end 333.542386 -20.607782)
		(width 0.12954)
		(layer "F.Cu")
		(net "ESPI_BMC_LPC_RST_N")
	)
	(segment
		(start 177.066956 -17.465802)
		(end 176.9618 -17.570958)
		(width 0.12954)
		(layer "F.Cu")
		(net "ESPI_BMC_LPC_RST_N")
	)
	(via
		(at 333.06004 -21.090128)
		(size 0.508)
		(drill 0.254)
		(layers "F.Cu" "B.Cu")
		(net "ESPI_BMC_LPC_RST_N")
	)
	(via
		(at 176.9618 -18.405348)
		(size 0.508)
		(drill 0.254)
		(layers "F.Cu" "B.Cu")
		(net "ESPI_BMC_LPC_RST_N")
	)
	(segment
		(start 192.923922 -26.612596)
		(end 193.99758 -29.204666)
		(width 0.127)
		(layer "In6.Cu")
		(net "ESPI_BMC_LPC_RST_N")
	)
	(segment
		(start 190.97117 -21.389848)
		(end 192.923922 -23.3426)
		(width 0.127)
		(layer "In6.Cu")
		(net "ESPI_BMC_LPC_RST_N")
	)
	(segment
		(start 185.10758 -20.881848)
		(end 187.350908 -20.881848)
		(width 0.127)
		(layer "In6.Cu")
		(net "ESPI_BMC_LPC_RST_N")
	)
	(segment
		(start 193.99758 -29.204666)
		(end 198.301102 -33.508188)
		(width 0.127)
		(layer "In6.Cu")
		(net "ESPI_BMC_LPC_RST_N")
	)
	(segment
		(start 192.923922 -23.3426)
		(end 192.923922 -26.612596)
		(width 0.127)
		(layer "In6.Cu")
		(net "ESPI_BMC_LPC_RST_N")
	)
	(segment
		(start 232.329482 -64.780668)
		(end 241.49431 -64.780668)
		(width 0.127)
		(layer "In6.Cu")
		(net "ESPI_BMC_LPC_RST_N")
	)
	(segment
		(start 187.350908 -20.881848)
		(end 187.858908 -21.389848)
		(width 0.127)
		(layer "In6.Cu")
		(net "ESPI_BMC_LPC_RST_N")
	)
	(segment
		(start 176.39538 -21.440648)
		(end 177.3428 -22.388068)
		(width 0.127)
		(layer "In6.Cu")
		(net "ESPI_BMC_LPC_RST_N")
	)
	(segment
		(start 217.28303 -49.734216)
		(end 232.329482 -64.780668)
		(width 0.127)
		(layer "In6.Cu")
		(net "ESPI_BMC_LPC_RST_N")
	)
	(segment
		(start 217.28303 -39.746682)
		(end 217.28303 -49.734216)
		(width 0.127)
		(layer "In6.Cu")
		(net "ESPI_BMC_LPC_RST_N")
	)
	(segment
		(start 297.089576 -33.080706)
		(end 303.926748 -26.243534)
		(width 0.127)
		(layer "In6.Cu")
		(net "ESPI_BMC_LPC_RST_N")
	)
	(segment
		(start 259.547106 -63.414148)
		(end 262.40359 -62.231016)
		(width 0.127)
		(layer "In6.Cu")
		(net "ESPI_BMC_LPC_RST_N")
	)
	(segment
		(start 333.06004 -22.642068)
		(end 333.06004 -21.090128)
		(width 0.127)
		(layer "In6.Cu")
		(net "ESPI_BMC_LPC_RST_N")
	)
	(segment
		(start 183.1975 -22.791928)
		(end 185.10758 -20.881848)
		(width 0.127)
		(layer "In6.Cu")
		(net "ESPI_BMC_LPC_RST_N")
	)
	(segment
		(start 179.95392 -22.388068)
		(end 180.35778 -22.791928)
		(width 0.127)
		(layer "In6.Cu")
		(net "ESPI_BMC_LPC_RST_N")
	)
	(segment
		(start 323.306694 -26.243534)
		(end 323.815964 -25.734264)
		(width 0.127)
		(layer "In6.Cu")
		(net "ESPI_BMC_LPC_RST_N")
	)
	(segment
		(start 180.35778 -22.791928)
		(end 183.1975 -22.791928)
		(width 0.127)
		(layer "In6.Cu")
		(net "ESPI_BMC_LPC_RST_N")
	)
	(segment
		(start 333.04988 -23.155148)
		(end 333.04988 -22.652228)
		(width 0.127)
		(layer "In6.Cu")
		(net "ESPI_BMC_LPC_RST_N")
	)
	(segment
		(start 176.9618 -18.405348)
		(end 176.39538 -18.971768)
		(width 0.127)
		(layer "In6.Cu")
		(net "ESPI_BMC_LPC_RST_N")
	)
	(segment
		(start 265.449558 -59.185048)
		(end 272.311114 -59.185048)
		(width 0.127)
		(layer "In6.Cu")
		(net "ESPI_BMC_LPC_RST_N")
	)
	(segment
		(start 187.858908 -21.389848)
		(end 190.97117 -21.389848)
		(width 0.127)
		(layer "In6.Cu")
		(net "ESPI_BMC_LPC_RST_N")
	)
	(segment
		(start 177.3428 -22.388068)
		(end 179.95392 -22.388068)
		(width 0.127)
		(layer "In6.Cu")
		(net "ESPI_BMC_LPC_RST_N")
	)
	(segment
		(start 211.044536 -33.508188)
		(end 217.28303 -39.746682)
		(width 0.127)
		(layer "In6.Cu")
		(net "ESPI_BMC_LPC_RST_N")
	)
	(segment
		(start 333.04988 -22.652228)
		(end 333.06004 -22.642068)
		(width 0.127)
		(layer "In6.Cu")
		(net "ESPI_BMC_LPC_RST_N")
	)
	(segment
		(start 242.86083 -63.414148)
		(end 259.547106 -63.414148)
		(width 0.127)
		(layer "In6.Cu")
		(net "ESPI_BMC_LPC_RST_N")
	)
	(segment
		(start 303.926748 -26.243534)
		(end 323.306694 -26.243534)
		(width 0.127)
		(layer "In6.Cu")
		(net "ESPI_BMC_LPC_RST_N")
	)
	(segment
		(start 297.089576 -34.406586)
		(end 297.089576 -33.080706)
		(width 0.127)
		(layer "In6.Cu")
		(net "ESPI_BMC_LPC_RST_N")
	)
	(segment
		(start 241.49431 -64.780668)
		(end 242.86083 -63.414148)
		(width 0.127)
		(layer "In6.Cu")
		(net "ESPI_BMC_LPC_RST_N")
	)
	(segment
		(start 198.301102 -33.508188)
		(end 211.044536 -33.508188)
		(width 0.127)
		(layer "In6.Cu")
		(net "ESPI_BMC_LPC_RST_N")
	)
	(segment
		(start 272.311114 -59.185048)
		(end 297.089576 -34.406586)
		(width 0.127)
		(layer "In6.Cu")
		(net "ESPI_BMC_LPC_RST_N")
	)
	(segment
		(start 330.470764 -25.734264)
		(end 333.04988 -23.155148)
		(width 0.127)
		(layer "In6.Cu")
		(net "ESPI_BMC_LPC_RST_N")
	)
	(segment
		(start 323.815964 -25.734264)
		(end 330.470764 -25.734264)
		(width 0.127)
		(layer "In6.Cu")
		(net "ESPI_BMC_LPC_RST_N")
	)
	(segment
		(start 176.39538 -18.971768)
		(end 176.39538 -21.440648)
		(width 0.127)
		(layer "In6.Cu")
		(net "ESPI_BMC_LPC_RST_N")
	)
	(segment
		(start 262.40359 -62.231016)
		(end 265.449558 -59.185048)
		(width 0.127)
		(layer "In6.Cu")
		(net "ESPI_BMC_LPC_RST_N")
	)
	(segment
		(start 331.364336 -24.681688)
		(end 330.88834 -25.157684)
		(width 0.12954)
		(layer "F.Cu")
		(net "ESPI_ALERT1_N_LPC_RCIN_N")
	)
	(segment
		(start 331.613256 -29.885386)
		(end 331.542136 -30.244288)
		(width 0.12954)
		(layer "F.Cu")
		(net "ESPI_ALERT1_N_LPC_RCIN_N")
	)
	(segment
		(start 333.096362 -38.196012)
		(end 333.225648 -38.345618)
		(width 0.0889)
		(layer "F.Cu")
		(net "ESPI_ALERT1_N_LPC_RCIN_N")
	)
	(segment
		(start 333.191104 -37.548058)
		(end 333.179674 -37.801804)
		(width 0.0889)
		(layer "F.Cu")
		(net "ESPI_ALERT1_N_LPC_RCIN_N")
	)
	(segment
		(start 330.703682 -18.396966)
		(end 332.124812 -18.396966)
		(width 0.12954)
		(layer "F.Cu")
		(net "ESPI_ALERT1_N_LPC_RCIN_N")
	)
	(segment
		(start 333.14386 -37.309552)
		(end 333.191104 -37.548058)
		(width 0.0889)
		(layer "F.Cu")
		(net "ESPI_ALERT1_N_LPC_RCIN_N")
	)
	(segment
		(start 333.096362 -37.926772)
		(end 333.096362 -38.196012)
		(width 0.0889)
		(layer "F.Cu")
		(net "ESPI_ALERT1_N_LPC_RCIN_N")
	)
	(segment
		(start 333.179674 -37.801804)
		(end 333.096362 -37.926772)
		(width 0.0889)
		(layer "F.Cu")
		(net "ESPI_ALERT1_N_LPC_RCIN_N")
	)
	(segment
		(start 331.364336 -23.307548)
		(end 331.364336 -24.681688)
		(width 0.12954)
		(layer "F.Cu")
		(net "ESPI_ALERT1_N_LPC_RCIN_N")
	)
	(segment
		(start 331.542136 -30.394402)
		(end 331.685392 -30.74035)
		(width 0.12954)
		(layer "F.Cu")
		(net "ESPI_ALERT1_N_LPC_RCIN_N")
	)
	(segment
		(start 331.956918 -31.011876)
		(end 331.956918 -33.795208)
		(width 0.0889)
		(layer "F.Cu")
		(net "ESPI_ALERT1_N_LPC_RCIN_N")
	)
	(segment
		(start 331.542136 -30.244288)
		(end 331.542136 -30.394402)
		(width 0.12954)
		(layer "F.Cu")
		(net "ESPI_ALERT1_N_LPC_RCIN_N")
	)
	(segment
		(start 329.76058 -19.568668)
		(end 330.99248 -20.800568)
		(width 0.12954)
		(layer "F.Cu")
		(net "ESPI_ALERT1_N_LPC_RCIN_N")
	)
	(segment
		(start 330.99248 -22.935692)
		(end 331.364336 -23.307548)
		(width 0.12954)
		(layer "F.Cu")
		(net "ESPI_ALERT1_N_LPC_RCIN_N")
	)
	(segment
		(start 329.76058 -19.340068)
		(end 330.703682 -18.396966)
		(width 0.12954)
		(layer "F.Cu")
		(net "ESPI_ALERT1_N_LPC_RCIN_N")
	)
	(segment
		(start 331.956918 -33.795208)
		(end 333.14386 -34.98215)
		(width 0.0889)
		(layer "F.Cu")
		(net "ESPI_ALERT1_N_LPC_RCIN_N")
	)
	(segment
		(start 331.756766 -30.811724)
		(end 331.956918 -31.011876)
		(width 0.0889)
		(layer "F.Cu")
		(net "ESPI_ALERT1_N_LPC_RCIN_N")
	)
	(segment
		(start 333.225648 -38.345618)
		(end 333.398114 -38.518084)
		(width 0.0889)
		(layer "F.Cu")
		(net "ESPI_ALERT1_N_LPC_RCIN_N")
	)
	(segment
		(start 330.99248 -20.800568)
		(end 330.99248 -22.935692)
		(width 0.12954)
		(layer "F.Cu")
		(net "ESPI_ALERT1_N_LPC_RCIN_N")
	)
	(segment
		(start 333.398114 -38.518084)
		(end 333.398114 -38.880288)
		(width 0.0889)
		(layer "F.Cu")
		(net "ESPI_ALERT1_N_LPC_RCIN_N")
	)
	(segment
		(start 331.685392 -30.74035)
		(end 331.756766 -30.811724)
		(width 0.12954)
		(layer "F.Cu")
		(net "ESPI_ALERT1_N_LPC_RCIN_N")
	)
	(segment
		(start 330.88834 -27.707082)
		(end 331.613256 -29.457396)
		(width 0.12954)
		(layer "F.Cu")
		(net "ESPI_ALERT1_N_LPC_RCIN_N")
	)
	(segment
		(start 333.14386 -34.98215)
		(end 333.14386 -37.309552)
		(width 0.0889)
		(layer "F.Cu")
		(net "ESPI_ALERT1_N_LPC_RCIN_N")
	)
	(segment
		(start 330.88834 -25.157684)
		(end 330.88834 -27.707082)
		(width 0.12954)
		(layer "F.Cu")
		(net "ESPI_ALERT1_N_LPC_RCIN_N")
	)
	(segment
		(start 331.613256 -29.457396)
		(end 331.613256 -29.885386)
		(width 0.12954)
		(layer "F.Cu")
		(net "ESPI_ALERT1_N_LPC_RCIN_N")
	)
	(segment
		(start 329.76058 -19.340068)
		(end 329.76058 -19.568668)
		(width 0.12954)
		(layer "F.Cu")
		(net "ESPI_ALERT1_N_LPC_RCIN_N")
	)
	(via
		(at 329.76058 -19.340068)
		(size 0.762)
		(drill 0.381)
		(layers "F.Cu" "B.Cu")
		(net "ESPI_ALERT1_N_LPC_RCIN_N")
	)
	(segment
		(start 351.285556 -61.178694)
		(end 351.90176 -61.178694)
		(width 0.13208)
		(layer "F.Cu")
		(net "DMI_CPU0_PCH_TX_DP<7>")
	)
	(segment
		(start 350.957896 -61.506354)
		(end 351.285556 -61.178694)
		(width 0.13208)
		(layer "F.Cu")
		(net "DMI_CPU0_PCH_TX_DP<7>")
	)
	(segment
		(start 366.628934 -227.367084)
		(end 366.62868 -227.36683)
		(width 0.13208)
		(layer "F.Cu")
		(net "DMI_CPU0_PCH_TX_DP<7>")
	)
	(segment
		(start 351.90176 -61.178694)
		(end 352.20402 -61.480954)
		(width 0.13208)
		(layer "F.Cu")
		(net "DMI_CPU0_PCH_TX_DP<7>")
	)
	(segment
		(start 366.62868 -227.36683)
		(end 366.62868 -226.831144)
		(width 0.13208)
		(layer "F.Cu")
		(net "DMI_CPU0_PCH_TX_DP<7>")
	)
	(segment
		(start 370.106448 -216.574116)
		(end 370.10848 -216.572846)
		(width 0.0889)
		(layer "In6.Cu")
		(net "DMI_CPU0_PCH_TX_DP<7>")
	)
	(segment
		(start 366.816894 -227.154994)
		(end 366.824768 -227.150422)
		(width 0.0889)
		(layer "In6.Cu")
		(net "DMI_CPU0_PCH_TX_DP<7>")
	)
	(segment
		(start 369.82273 -217.07856)
		(end 369.82273 -217.064336)
		(width 0.0889)
		(layer "In6.Cu")
		(net "DMI_CPU0_PCH_TX_DP<7>")
	)
	(segment
		(start 350.32188 -75.963018)
		(end 350.402652 -75.810872)
		(width 0.14732)
		(layer "In6.Cu")
		(net "DMI_CPU0_PCH_TX_DP<7>")
	)
	(segment
		(start 387.821678 -190.478918)
		(end 389.811514 -179.197762)
		(width 0.14732)
		(layer "In6.Cu")
		(net "DMI_CPU0_PCH_TX_DP<7>")
	)
	(segment
		(start 370.11102 -216.571576)
		(end 370.114322 -216.569544)
		(width 0.0889)
		(layer "In6.Cu")
		(net "DMI_CPU0_PCH_TX_DP<7>")
	)
	(segment
		(start 389.811514 -179.197762)
		(end 384.187192 -147.301458)
		(width 0.14732)
		(layer "In6.Cu")
		(net "DMI_CPU0_PCH_TX_DP<7>")
	)
	(segment
		(start 369.165632 -221.458282)
		(end 369.17249 -221.454472)
		(width 0.0889)
		(layer "In6.Cu")
		(net "DMI_CPU0_PCH_TX_DP<7>")
	)
	(segment
		(start 386.068316 -191.998092)
		(end 387.42112 -191.050926)
		(width 0.14732)
		(layer "In6.Cu")
		(net "DMI_CPU0_PCH_TX_DP<7>")
	)
	(segment
		(start 348.947232 -69.994272)
		(end 347.456506 -68.503546)
		(width 0.14732)
		(layer "In6.Cu")
		(net "DMI_CPU0_PCH_TX_DP<7>")
	)
	(segment
		(start 371.604032 -212.695028)
		(end 371.703092 -212.595968)
		(width 0.0889)
		(layer "In6.Cu")
		(net "DMI_CPU0_PCH_TX_DP<7>")
	)
	(segment
		(start 369.353084 -219.506038)
		(end 369.353084 -219.490544)
		(width 0.0889)
		(layer "In6.Cu")
		(net "DMI_CPU0_PCH_TX_DP<7>")
	)
	(segment
		(start 369.17249 -221.454472)
		(end 369.174522 -221.453202)
		(width 0.0889)
		(layer "In6.Cu")
		(net "DMI_CPU0_PCH_TX_DP<7>")
	)
	(segment
		(start 369.16487 -221.45879)
		(end 369.165632 -221.458282)
		(width 0.0889)
		(layer "In6.Cu")
		(net "DMI_CPU0_PCH_TX_DP<7>")
	)
	(segment
		(start 351.443798 -63.511938)
		(end 351.443798 -63.321692)
		(width 0.14732)
		(layer "In6.Cu")
		(net "DMI_CPU0_PCH_TX_DP<7>")
	)
	(segment
		(start 370.102638 -218.204288)
		(end 370.105432 -218.202764)
		(width 0.0889)
		(layer "In6.Cu")
		(net "DMI_CPU0_PCH_TX_DP<7>")
	)
	(segment
		(start 368.88293 -220.327474)
		(end 368.88293 -220.319854)
		(width 0.0889)
		(layer "In6.Cu")
		(net "DMI_CPU0_PCH_TX_DP<7>")
	)
	(segment
		(start 370.105432 -218.202764)
		(end 370.106956 -218.202002)
		(width 0.0889)
		(layer "In6.Cu")
		(net "DMI_CPU0_PCH_TX_DP<7>")
	)
	(segment
		(start 367.473484 -224.404936)
		(end 367.473484 -224.379536)
		(width 0.0889)
		(layer "In6.Cu")
		(net "DMI_CPU0_PCH_TX_DP<7>")
	)
	(segment
		(start 350.602804 -76.461874)
		(end 350.45015 -76.381102)
		(width 0.14732)
		(layer "In6.Cu")
		(net "DMI_CPU0_PCH_TX_DP<7>")
	)
	(segment
		(start 367.473484 -226.017328)
		(end 367.473484 -225.99523)
		(width 0.0889)
		(layer "In6.Cu")
		(net "DMI_CPU0_PCH_TX_DP<7>")
	)
	(segment
		(start 367.755678 -225.527616)
		(end 367.764568 -225.522536)
		(width 0.0889)
		(layer "In6.Cu")
		(net "DMI_CPU0_PCH_TX_DP<7>")
	)
	(segment
		(start 351.644458 -80.271112)
		(end 351.72523 -80.118712)
		(width 0.14732)
		(layer "In6.Cu")
		(net "DMI_CPU0_PCH_TX_DP<7>")
	)
	(segment
		(start 350.121982 -75.312524)
		(end 349.993966 -74.894694)
		(width 0.14732)
		(layer "In6.Cu")
		(net "DMI_CPU0_PCH_TX_DP<7>")
	)
	(segment
		(start 368.695478 -222.272098)
		(end 368.704368 -222.267018)
		(width 0.0889)
		(layer "In6.Cu")
		(net "DMI_CPU0_PCH_TX_DP<7>")
	)
	(segment
		(start 351.397062 -79.049626)
		(end 350.602804 -76.461874)
		(width 0.14732)
		(layer "In6.Cu")
		(net "DMI_CPU0_PCH_TX_DP<7>")
	)
	(segment
		(start 369.635278 -219.01658)
		(end 369.644168 -219.0115)
		(width 0.0889)
		(layer "In6.Cu")
		(net "DMI_CPU0_PCH_TX_DP<7>")
	)
	(segment
		(start 371.660928 -211.47151)
		(end 371.660928 -209.594958)
		(width 0.14732)
		(layer "In6.Cu")
		(net "DMI_CPU0_PCH_TX_DP<7>")
	)
	(segment
		(start 351.925382 -80.769714)
		(end 351.772728 -80.688942)
		(width 0.14732)
		(layer "In6.Cu")
		(net "DMI_CPU0_PCH_TX_DP<7>")
	)
	(segment
		(start 371.660928 -211.493608)
		(end 371.660928 -211.47151)
		(width 0.0889)
		(layer "In6.Cu")
		(net "DMI_CPU0_PCH_TX_DP<7>")
	)
	(segment
		(start 370.104162 -216.57564)
		(end 370.106448 -216.574116)
		(width 0.0889)
		(layer "In6.Cu")
		(net "DMI_CPU0_PCH_TX_DP<7>")
	)
	(segment
		(start 366.472216 -227.102162)
		(end 366.493298 -227.18014)
		(width 0.0889)
		(layer "In6.Cu")
		(net "DMI_CPU0_PCH_TX_DP<7>")
	)
	(segment
		(start 351.699068 -63.066422)
		(end 351.889314 -63.066422)
		(width 0.14732)
		(layer "In6.Cu")
		(net "DMI_CPU0_PCH_TX_DP<7>")
	)
	(segment
		(start 371.703092 -213.058248)
		(end 371.604032 -212.959188)
		(width 0.0889)
		(layer "In6.Cu")
		(net "DMI_CPU0_PCH_TX_DP<7>")
	)
	(segment
		(start 369.166394 -220.810074)
		(end 369.165632 -220.809566)
		(width 0.0889)
		(layer "In6.Cu")
		(net "DMI_CPU0_PCH_TX_DP<7>")
	)
	(segment
		(start 349.832422 -73.952862)
		(end 349.832422 -72.131174)
		(width 0.14732)
		(layer "In6.Cu")
		(net "DMI_CPU0_PCH_TX_DP<7>")
	)
	(segment
		(start 351.72523 -80.118712)
		(end 351.597214 -79.701136)
		(width 0.14732)
		(layer "In6.Cu")
		(net "DMI_CPU0_PCH_TX_DP<7>")
	)
	(segment
		(start 351.44456 -79.620364)
		(end 351.31629 -79.202534)
		(width 0.14732)
		(layer "In6.Cu")
		(net "DMI_CPU0_PCH_TX_DP<7>")
	)
	(segment
		(start 369.174522 -220.814646)
		(end 369.166394 -220.810074)
		(width 0.0889)
		(layer "In6.Cu")
		(net "DMI_CPU0_PCH_TX_DP<7>")
	)
	(segment
		(start 371.703092 -211.869528)
		(end 371.703092 -211.535772)
		(width 0.0889)
		(layer "In6.Cu")
		(net "DMI_CPU0_PCH_TX_DP<7>")
	)
	(segment
		(start 366.62868 -226.831144)
		(end 366.472216 -227.102162)
		(width 0.0889)
		(layer "In6.Cu")
		(net "DMI_CPU0_PCH_TX_DP<7>")
	)
	(segment
		(start 349.993966 -74.894694)
		(end 350.074738 -74.742294)
		(width 0.14732)
		(layer "In6.Cu")
		(net "DMI_CPU0_PCH_TX_DP<7>")
	)
	(segment
		(start 367.286032 -226.341686)
		(end 367.294922 -226.336606)
		(width 0.0889)
		(layer "In6.Cu")
		(net "DMI_CPU0_PCH_TX_DP<7>")
	)
	(segment
		(start 371.604032 -212.232748)
		(end 371.604032 -211.968588)
		(width 0.0889)
		(layer "In6.Cu")
		(net "DMI_CPU0_PCH_TX_DP<7>")
	)
	(segment
		(start 351.443798 -63.321692)
		(end 351.699068 -63.066422)
		(width 0.14732)
		(layer "In6.Cu")
		(net "DMI_CPU0_PCH_TX_DP<7>")
	)
	(segment
		(start 370.76253 -215.436704)
		(end 370.76253 -215.42121)
		(width 0.0889)
		(layer "In6.Cu")
		(net "DMI_CPU0_PCH_TX_DP<7>")
	)
	(segment
		(start 380.299468 -199.012048)
		(end 383.161032 -196.150484)
		(width 0.14732)
		(layer "In6.Cu")
		(net "DMI_CPU0_PCH_TX_DP<7>")
	)
	(segment
		(start 370.114322 -217.559128)
		(end 370.105432 -217.554048)
		(width 0.0889)
		(layer "In6.Cu")
		(net "DMI_CPU0_PCH_TX_DP<7>")
	)
	(segment
		(start 347.456506 -68.503546)
		(end 347.456506 -65.698116)
		(width 0.14732)
		(layer "In6.Cu")
		(net "DMI_CPU0_PCH_TX_DP<7>")
	)
	(segment
		(start 367.27384 -226.348798)
		(end 367.286032 -226.341686)
		(width 0.0889)
		(layer "In6.Cu")
		(net "DMI_CPU0_PCH_TX_DP<7>")
	)
	(segment
		(start 370.575078 -215.761062)
		(end 370.583968 -215.755982)
		(width 0.0889)
		(layer "In6.Cu")
		(net "DMI_CPU0_PCH_TX_DP<7>")
	)
	(segment
		(start 350.274636 -75.393296)
		(end 350.121982 -75.312524)
		(width 0.14732)
		(layer "In6.Cu")
		(net "DMI_CPU0_PCH_TX_DP<7>")
	)
	(segment
		(start 352.703892 -61.186314)
		(end 352.49866 -61.186314)
		(width 0.14732)
		(layer "In6.Cu")
		(net "DMI_CPU0_PCH_TX_DP<7>")
	)
	(segment
		(start 350.402652 -75.810872)
		(end 350.274636 -75.393296)
		(width 0.14732)
		(layer "In6.Cu")
		(net "DMI_CPU0_PCH_TX_DP<7>")
	)
	(segment
		(start 352.844862 -62.110874)
		(end 352.844862 -61.327284)
		(width 0.14732)
		(layer "In6.Cu")
		(net "DMI_CPU0_PCH_TX_DP<7>")
	)
	(segment
		(start 351.772728 -80.688942)
		(end 351.644458 -80.271112)
		(width 0.14732)
		(layer "In6.Cu")
		(net "DMI_CPU0_PCH_TX_DP<7>")
	)
	(segment
		(start 349.072454 -64.082168)
		(end 350.873568 -64.082168)
		(width 0.14732)
		(layer "In6.Cu")
		(net "DMI_CPU0_PCH_TX_DP<7>")
	)
	(segment
		(start 371.660928 -209.594958)
		(end 371.906292 -208.19999)
		(width 0.14732)
		(layer "In6.Cu")
		(net "DMI_CPU0_PCH_TX_DP<7>")
	)
	(segment
		(start 349.832422 -72.131174)
		(end 348.947232 -69.994272)
		(width 0.14732)
		(layer "In6.Cu")
		(net "DMI_CPU0_PCH_TX_DP<7>")
	)
	(segment
		(start 371.703092 -211.535772)
		(end 371.660928 -211.493608)
		(width 0.0889)
		(layer "In6.Cu")
		(net "DMI_CPU0_PCH_TX_DP<7>")
	)
	(segment
		(start 371.703092 -212.595968)
		(end 371.703092 -212.331808)
		(width 0.0889)
		(layer "In6.Cu")
		(net "DMI_CPU0_PCH_TX_DP<7>")
	)
	(segment
		(start 352.14433 -62.62116)
		(end 352.3996 -62.36589)
		(width 0.14732)
		(layer "In6.Cu")
		(net "DMI_CPU0_PCH_TX_DP<7>")
	)
	(segment
		(start 352.589846 -62.36589)
		(end 352.844862 -62.110874)
		(width 0.14732)
		(layer "In6.Cu")
		(net "DMI_CPU0_PCH_TX_DP<7>")
	)
	(segment
		(start 371.906292 -208.19999)
		(end 376.456448 -201.702416)
		(width 0.14732)
		(layer "In6.Cu")
		(net "DMI_CPU0_PCH_TX_DP<7>")
	)
	(segment
		(start 352.49866 -61.186314)
		(end 352.20402 -61.480954)
		(width 0.14732)
		(layer "In6.Cu")
		(net "DMI_CPU0_PCH_TX_DP<7>")
	)
	(segment
		(start 370.292884 -216.25052)
		(end 370.292884 -216.235026)
		(width 0.0889)
		(layer "In6.Cu")
		(net "DMI_CPU0_PCH_TX_DP<7>")
	)
	(segment
		(start 370.10848 -216.572846)
		(end 370.11102 -216.571576)
		(width 0.0889)
		(layer "In6.Cu")
		(net "DMI_CPU0_PCH_TX_DP<7>")
	)
	(segment
		(start 371.703092 -214.306912)
		(end 371.703092 -213.058248)
		(width 0.0889)
		(layer "In6.Cu")
		(net "DMI_CPU0_PCH_TX_DP<7>")
	)
	(segment
		(start 370.099336 -216.578434)
		(end 370.104162 -216.57564)
		(width 0.0889)
		(layer "In6.Cu")
		(net "DMI_CPU0_PCH_TX_DP<7>")
	)
	(segment
		(start 369.159536 -221.461838)
		(end 369.16487 -221.45879)
		(width 0.0889)
		(layer "In6.Cu")
		(net "DMI_CPU0_PCH_TX_DP<7>")
	)
	(segment
		(start 370.106956 -218.202002)
		(end 370.114322 -218.197684)
		(width 0.0889)
		(layer "In6.Cu")
		(net "DMI_CPU0_PCH_TX_DP<7>")
	)
	(segment
		(start 384.187192 -147.301458)
		(end 352.320098 -82.056224)
		(width 0.14732)
		(layer "In6.Cu")
		(net "DMI_CPU0_PCH_TX_DP<7>")
	)
	(segment
		(start 370.099336 -218.20632)
		(end 370.102638 -218.204288)
		(width 0.0889)
		(layer "In6.Cu")
		(net "DMI_CPU0_PCH_TX_DP<7>")
	)
	(segment
		(start 376.456448 -201.702416)
		(end 380.299468 -199.012048)
		(width 0.14732)
		(layer "In6.Cu")
		(net "DMI_CPU0_PCH_TX_DP<7>")
	)
	(segment
		(start 370.114322 -216.569544)
		(end 370.114322 -216.569798)
		(width 0.0889)
		(layer "In6.Cu")
		(net "DMI_CPU0_PCH_TX_DP<7>")
	)
	(segment
		(start 371.122194 -214.88781)
		(end 371.703092 -214.306912)
		(width 0.0889)
		(layer "In6.Cu")
		(net "DMI_CPU0_PCH_TX_DP<7>")
	)
	(segment
		(start 368.225832 -223.085914)
		(end 368.234722 -223.080834)
		(width 0.0889)
		(layer "In6.Cu")
		(net "DMI_CPU0_PCH_TX_DP<7>")
	)
	(segment
		(start 371.604032 -212.959188)
		(end 371.604032 -212.695028)
		(width 0.0889)
		(layer "In6.Cu")
		(net "DMI_CPU0_PCH_TX_DP<7>")
	)
	(segment
		(start 351.397062 -79.050134)
		(end 351.397062 -79.049626)
		(width 0.14732)
		(layer "In6.Cu")
		(net "DMI_CPU0_PCH_TX_DP<7>")
	)
	(segment
		(start 352.844862 -61.327284)
		(end 352.703892 -61.186314)
		(width 0.14732)
		(layer "In6.Cu")
		(net "DMI_CPU0_PCH_TX_DP<7>")
	)
	(segment
		(start 352.14433 -62.811406)
		(end 352.14433 -62.62116)
		(width 0.14732)
		(layer "In6.Cu")
		(net "DMI_CPU0_PCH_TX_DP<7>")
	)
	(segment
		(start 347.456506 -65.698116)
		(end 349.072454 -64.082168)
		(width 0.14732)
		(layer "In6.Cu")
		(net "DMI_CPU0_PCH_TX_DP<7>")
	)
	(segment
		(start 350.074738 -74.742294)
		(end 349.832422 -73.952862)
		(width 0.14732)
		(layer "In6.Cu")
		(net "DMI_CPU0_PCH_TX_DP<7>")
	)
	(segment
		(start 383.161032 -196.150484)
		(end 386.068316 -191.998092)
		(width 0.14732)
		(layer "In6.Cu")
		(net "DMI_CPU0_PCH_TX_DP<7>")
	)
	(segment
		(start 366.815878 -227.155502)
		(end 366.816894 -227.154994)
		(width 0.0889)
		(layer "In6.Cu")
		(net "DMI_CPU0_PCH_TX_DP<7>")
	)
	(segment
		(start 369.165632 -219.830396)
		(end 369.174522 -219.825316)
		(width 0.0889)
		(layer "In6.Cu")
		(net "DMI_CPU0_PCH_TX_DP<7>")
	)
	(segment
		(start 351.597214 -79.701136)
		(end 351.44456 -79.620364)
		(width 0.14732)
		(layer "In6.Cu")
		(net "DMI_CPU0_PCH_TX_DP<7>")
	)
	(segment
		(start 371.604032 -211.968588)
		(end 371.703092 -211.869528)
		(width 0.0889)
		(layer "In6.Cu")
		(net "DMI_CPU0_PCH_TX_DP<7>")
	)
	(segment
		(start 350.873568 -64.082168)
		(end 351.443798 -63.511938)
		(width 0.14732)
		(layer "In6.Cu")
		(net "DMI_CPU0_PCH_TX_DP<7>")
	)
	(segment
		(start 368.413284 -222.761556)
		(end 368.413284 -222.746062)
		(width 0.0889)
		(layer "In6.Cu")
		(net "DMI_CPU0_PCH_TX_DP<7>")
	)
	(segment
		(start 350.45015 -76.381102)
		(end 350.32188 -75.963018)
		(width 0.14732)
		(layer "In6.Cu")
		(net "DMI_CPU0_PCH_TX_DP<7>")
	)
	(segment
		(start 387.42112 -191.050926)
		(end 387.821678 -190.478918)
		(width 0.14732)
		(layer "In6.Cu")
		(net "DMI_CPU0_PCH_TX_DP<7>")
	)
	(segment
		(start 367.764568 -224.88398)
		(end 367.755678 -224.8789)
		(width 0.0889)
		(layer "In6.Cu")
		(net "DMI_CPU0_PCH_TX_DP<7>")
	)
	(segment
		(start 352.320098 -82.056224)
		(end 351.925382 -80.769714)
		(width 0.14732)
		(layer "In6.Cu")
		(net "DMI_CPU0_PCH_TX_DP<7>")
	)
	(segment
		(start 369.15344 -219.837508)
		(end 369.165632 -219.830396)
		(width 0.0889)
		(layer "In6.Cu")
		(net "DMI_CPU0_PCH_TX_DP<7>")
	)
	(segment
		(start 367.94313 -223.584262)
		(end 367.94313 -223.561402)
		(width 0.0889)
		(layer "In6.Cu")
		(net "DMI_CPU0_PCH_TX_DP<7>")
	)
	(segment
		(start 352.3996 -62.36589)
		(end 352.589846 -62.36589)
		(width 0.14732)
		(layer "In6.Cu")
		(net "DMI_CPU0_PCH_TX_DP<7>")
	)
	(segment
		(start 351.889314 -63.066422)
		(end 352.14433 -62.811406)
		(width 0.14732)
		(layer "In6.Cu")
		(net "DMI_CPU0_PCH_TX_DP<7>")
	)
	(segment
		(start 371.703092 -212.331808)
		(end 371.604032 -212.232748)
		(width 0.0889)
		(layer "In6.Cu")
		(net "DMI_CPU0_PCH_TX_DP<7>")
	)
	(segment
		(start 351.31629 -79.202534)
		(end 351.397062 -79.050134)
		(width 0.14732)
		(layer "In6.Cu")
		(net "DMI_CPU0_PCH_TX_DP<7>")
	)
	(arc
		(start 367.764568 -225.522536)
		(mid 367.891822 -225.39257)
		(end 367.942876 -225.21799)
		(width 0.0889)
		(layer "In6.Cu")
		(net "DMI_CPU0_PCH_TX_DP<7>")
	)
	(arc
		(start 369.82273 -217.064336)
		(mid 369.896721 -216.78477)
		(end 370.099336 -216.578434)
		(width 0.0889)
		(layer "In6.Cu")
		(net "DMI_CPU0_PCH_TX_DP<7>")
	)
	(arc
		(start 370.114322 -218.197684)
		(mid 370.292919 -217.878406)
		(end 370.114322 -217.559128)
		(width 0.0889)
		(layer "In6.Cu")
		(net "DMI_CPU0_PCH_TX_DP<7>")
	)
	(arc
		(start 368.88293 -221.94774)
		(mid 368.956921 -221.668174)
		(end 369.159536 -221.461838)
		(width 0.0889)
		(layer "In6.Cu")
		(net "DMI_CPU0_PCH_TX_DP<7>")
	)
	(arc
		(start 369.353084 -219.490544)
		(mid 369.432454 -219.21681)
		(end 369.635278 -219.01658)
		(width 0.0889)
		(layer "In6.Cu")
		(net "DMI_CPU0_PCH_TX_DP<7>")
	)
	(arc
		(start 370.114322 -216.569798)
		(mid 370.245236 -216.433438)
		(end 370.292884 -216.25052)
		(width 0.0889)
		(layer "In6.Cu")
		(net "DMI_CPU0_PCH_TX_DP<7>")
	)
	(arc
		(start 366.824768 -227.150422)
		(mid 366.955682 -227.014062)
		(end 367.00333 -226.831144)
		(width 0.0889)
		(layer "In6.Cu")
		(net "DMI_CPU0_PCH_TX_DP<7>")
	)
	(arc
		(start 368.234722 -223.080834)
		(mid 368.365636 -222.944474)
		(end 368.413284 -222.761556)
		(width 0.0889)
		(layer "In6.Cu")
		(net "DMI_CPU0_PCH_TX_DP<7>")
	)
	(arc
		(start 369.165632 -220.809566)
		(mid 368.96056 -220.605887)
		(end 368.88293 -220.327474)
		(width 0.0889)
		(layer "In6.Cu")
		(net "DMI_CPU0_PCH_TX_DP<7>")
	)
	(arc
		(start 367.294922 -226.336606)
		(mid 367.425836 -226.200246)
		(end 367.473484 -226.017328)
		(width 0.0889)
		(layer "In6.Cu")
		(net "DMI_CPU0_PCH_TX_DP<7>")
	)
	(arc
		(start 371.044724 -214.947246)
		(mid 371.085394 -214.920052)
		(end 371.122194 -214.88781)
		(width 0.0889)
		(layer "In6.Cu")
		(net "DMI_CPU0_PCH_TX_DP<7>")
	)
	(arc
		(start 367.473484 -224.379536)
		(mid 367.551595 -224.102587)
		(end 367.755932 -223.899984)
		(width 0.0889)
		(layer "In6.Cu")
		(net "DMI_CPU0_PCH_TX_DP<7>")
	)
	(arc
		(start 369.174522 -219.825316)
		(mid 369.305436 -219.688956)
		(end 369.353084 -219.506038)
		(width 0.0889)
		(layer "In6.Cu")
		(net "DMI_CPU0_PCH_TX_DP<7>")
	)
	(arc
		(start 367.00333 -226.831144)
		(mid 367.075565 -226.55462)
		(end 367.27384 -226.348798)
		(width 0.0889)
		(layer "In6.Cu")
		(net "DMI_CPU0_PCH_TX_DP<7>")
	)
	(arc
		(start 369.82273 -218.692222)
		(mid 369.896721 -218.412656)
		(end 370.099336 -218.20632)
		(width 0.0889)
		(layer "In6.Cu")
		(net "DMI_CPU0_PCH_TX_DP<7>")
	)
	(arc
		(start 370.583968 -215.755982)
		(mid 370.714882 -215.619622)
		(end 370.76253 -215.436704)
		(width 0.0889)
		(layer "In6.Cu")
		(net "DMI_CPU0_PCH_TX_DP<7>")
	)
	(arc
		(start 368.88293 -220.319854)
		(mid 368.955165 -220.04333)
		(end 369.15344 -219.837508)
		(width 0.0889)
		(layer "In6.Cu")
		(net "DMI_CPU0_PCH_TX_DP<7>")
	)
	(arc
		(start 367.942876 -225.21799)
		(mid 367.943073 -225.210625)
		(end 367.94313 -225.203258)
		(width 0.0889)
		(layer "In6.Cu")
		(net "DMI_CPU0_PCH_TX_DP<7>")
	)
	(arc
		(start 370.76253 -215.42121)
		(mid 370.8419 -215.147476)
		(end 371.044724 -214.947246)
		(width 0.0889)
		(layer "In6.Cu")
		(net "DMI_CPU0_PCH_TX_DP<7>")
	)
	(arc
		(start 367.755932 -223.899984)
		(mid 367.890865 -223.76663)
		(end 367.94313 -223.584262)
		(width 0.0889)
		(layer "In6.Cu")
		(net "DMI_CPU0_PCH_TX_DP<7>")
	)
	(arc
		(start 368.413284 -222.746062)
		(mid 368.492654 -222.472328)
		(end 368.695478 -222.272098)
		(width 0.0889)
		(layer "In6.Cu")
		(net "DMI_CPU0_PCH_TX_DP<7>")
	)
	(arc
		(start 367.473484 -225.99523)
		(mid 367.554395 -225.725102)
		(end 367.755678 -225.527616)
		(width 0.0889)
		(layer "In6.Cu")
		(net "DMI_CPU0_PCH_TX_DP<7>")
	)
	(arc
		(start 367.755678 -224.8789)
		(mid 367.552855 -224.678669)
		(end 367.473484 -224.404936)
		(width 0.0889)
		(layer "In6.Cu")
		(net "DMI_CPU0_PCH_TX_DP<7>")
	)
	(arc
		(start 370.105432 -217.554048)
		(mid 369.901951 -217.353244)
		(end 369.82273 -217.07856)
		(width 0.0889)
		(layer "In6.Cu")
		(net "DMI_CPU0_PCH_TX_DP<7>")
	)
	(arc
		(start 366.493298 -227.18014)
		(mid 366.657394 -227.204487)
		(end 366.815878 -227.155502)
		(width 0.0889)
		(layer "In6.Cu")
		(net "DMI_CPU0_PCH_TX_DP<7>")
	)
	(arc
		(start 367.94313 -225.203258)
		(mid 367.895451 -225.020358)
		(end 367.764568 -224.88398)
		(width 0.0889)
		(layer "In6.Cu")
		(net "DMI_CPU0_PCH_TX_DP<7>")
	)
	(arc
		(start 367.94313 -223.561402)
		(mid 368.022349 -223.286717)
		(end 368.225832 -223.085914)
		(width 0.0889)
		(layer "In6.Cu")
		(net "DMI_CPU0_PCH_TX_DP<7>")
	)
	(arc
		(start 369.174522 -221.453202)
		(mid 369.353119 -221.133924)
		(end 369.174522 -220.814646)
		(width 0.0889)
		(layer "In6.Cu")
		(net "DMI_CPU0_PCH_TX_DP<7>")
	)
	(arc
		(start 370.292884 -216.235026)
		(mid 370.372254 -215.961292)
		(end 370.575078 -215.761062)
		(width 0.0889)
		(layer "In6.Cu")
		(net "DMI_CPU0_PCH_TX_DP<7>")
	)
	(arc
		(start 369.644168 -219.0115)
		(mid 369.775082 -218.87514)
		(end 369.82273 -218.692222)
		(width 0.0889)
		(layer "In6.Cu")
		(net "DMI_CPU0_PCH_TX_DP<7>")
	)
	(arc
		(start 368.704368 -222.267018)
		(mid 368.835282 -222.130658)
		(end 368.88293 -221.94774)
		(width 0.0889)
		(layer "In6.Cu")
		(net "DMI_CPU0_PCH_TX_DP<7>")
	)
	(segment
		(start 349.69704 -62.967108)
		(end 350.379284 -62.967108)
		(width 0.13208)
		(layer "F.Cu")
		(net "DMI_CPU0_PCH_TX_DP<6>")
	)
	(segment
		(start 365.68888 -228.994716)
		(end 365.68888 -228.45903)
		(width 0.13208)
		(layer "F.Cu")
		(net "DMI_CPU0_PCH_TX_DP<6>")
	)
	(segment
		(start 350.379284 -62.967108)
		(end 350.682052 -63.269876)
		(width 0.13208)
		(layer "F.Cu")
		(net "DMI_CPU0_PCH_TX_DP<6>")
	)
	(segment
		(start 349.3516 -63.312548)
		(end 349.69704 -62.967108)
		(width 0.13208)
		(layer "F.Cu")
		(net "DMI_CPU0_PCH_TX_DP<6>")
	)
	(segment
		(start 365.689134 -228.99497)
		(end 365.68888 -228.994716)
		(width 0.13208)
		(layer "F.Cu")
		(net "DMI_CPU0_PCH_TX_DP<6>")
	)
	(segment
		(start 349.595694 -77.332078)
		(end 349.465646 -76.915264)
		(width 0.14732)
		(layer "In6.Cu")
		(net "DMI_CPU0_PCH_TX_DP<6>")
	)
	(segment
		(start 368.321082 -221.623382)
		(end 368.333274 -221.61627)
		(width 0.0889)
		(layer "In6.Cu")
		(net "DMI_CPU0_PCH_TX_DP<6>")
	)
	(segment
		(start 367.372646 -223.256348)
		(end 367.380774 -223.251776)
		(width 0.0889)
		(layer "In6.Cu")
		(net "DMI_CPU0_PCH_TX_DP<6>")
	)
	(segment
		(start 367.19383 -225.225356)
		(end 367.19383 -225.187764)
		(width 0.0889)
		(layer "In6.Cu")
		(net "DMI_CPU0_PCH_TX_DP<6>")
	)
	(segment
		(start 349.798894 -77.982318)
		(end 349.878904 -77.82941)
		(width 0.14732)
		(layer "In6.Cu")
		(net "DMI_CPU0_PCH_TX_DP<6>")
	)
	(segment
		(start 370.013484 -215.44661)
		(end 370.013484 -215.435688)
		(width 0.0889)
		(layer "In6.Cu")
		(net "DMI_CPU0_PCH_TX_DP<6>")
	)
	(segment
		(start 370.944648 -214.395304)
		(end 370.944648 -212.79485)
		(width 0.0889)
		(layer "In6.Cu")
		(net "DMI_CPU0_PCH_TX_DP<6>")
	)
	(segment
		(start 370.195348 -215.11514)
		(end 370.200936 -215.111838)
		(width 0.0889)
		(layer "In6.Cu")
		(net "DMI_CPU0_PCH_TX_DP<6>")
	)
	(segment
		(start 346.833698 -65.316862)
		(end 349.193612 -62.956948)
		(width 0.14732)
		(layer "In6.Cu")
		(net "DMI_CPU0_PCH_TX_DP<6>")
	)
	(segment
		(start 369.252246 -216.745058)
		(end 369.260374 -216.740486)
		(width 0.0889)
		(layer "In6.Cu")
		(net "DMI_CPU0_PCH_TX_DP<6>")
	)
	(segment
		(start 349.545656 -76.762356)
		(end 349.415354 -76.345034)
		(width 0.14732)
		(layer "In6.Cu")
		(net "DMI_CPU0_PCH_TX_DP<6>")
	)
	(segment
		(start 365.68888 -228.45903)
		(end 365.532416 -228.188012)
		(width 0.0889)
		(layer "In6.Cu")
		(net "DMI_CPU0_PCH_TX_DP<6>")
	)
	(segment
		(start 350.554036 -80.401414)
		(end 350.132142 -79.049372)
		(width 0.14732)
		(layer "In6.Cu")
		(net "DMI_CPU0_PCH_TX_DP<6>")
	)
	(segment
		(start 349.132398 -75.84821)
		(end 349.132398 -71.950326)
		(width 0.14732)
		(layer "In6.Cu")
		(net "DMI_CPU0_PCH_TX_DP<6>")
	)
	(segment
		(start 366.254284 -226.84105)
		(end 366.254284 -226.822508)
		(width 0.0889)
		(layer "In6.Cu")
		(net "DMI_CPU0_PCH_TX_DP<6>")
	)
	(segment
		(start 349.193612 -62.956948)
		(end 350.369124 -62.956948)
		(width 0.14732)
		(layer "In6.Cu")
		(net "DMI_CPU0_PCH_TX_DP<6>")
	)
	(segment
		(start 368.133884 -221.957646)
		(end 368.133884 -221.939104)
		(width 0.0889)
		(layer "In6.Cu")
		(net "DMI_CPU0_PCH_TX_DP<6>")
	)
	(segment
		(start 369.07343 -218.707716)
		(end 369.07343 -218.692222)
		(width 0.0889)
		(layer "In6.Cu")
		(net "DMI_CPU0_PCH_TX_DP<6>")
	)
	(segment
		(start 367.842546 -222.442278)
		(end 367.851436 -222.437198)
		(width 0.0889)
		(layer "In6.Cu")
		(net "DMI_CPU0_PCH_TX_DP<6>")
	)
	(segment
		(start 369.260374 -216.740486)
		(end 369.261136 -216.739978)
		(width 0.0889)
		(layer "In6.Cu")
		(net "DMI_CPU0_PCH_TX_DP<6>")
	)
	(segment
		(start 387.092952 -189.192154)
		(end 389.02386 -178.237134)
		(width 0.14732)
		(layer "In6.Cu")
		(net "DMI_CPU0_PCH_TX_DP<6>")
	)
	(segment
		(start 365.784384 -227.659184)
		(end 365.784384 -227.64496)
		(width 0.0889)
		(layer "In6.Cu")
		(net "DMI_CPU0_PCH_TX_DP<6>")
	)
	(segment
		(start 366.441482 -226.506786)
		(end 366.442244 -226.506278)
		(width 0.0889)
		(layer "In6.Cu")
		(net "DMI_CPU0_PCH_TX_DP<6>")
	)
	(segment
		(start 350.08185 -78.479396)
		(end 349.928942 -78.399132)
		(width 0.14732)
		(layer "In6.Cu")
		(net "DMI_CPU0_PCH_TX_DP<6>")
	)
	(segment
		(start 368.133884 -220.32849)
		(end 368.133884 -220.311218)
		(width 0.0889)
		(layer "In6.Cu")
		(net "DMI_CPU0_PCH_TX_DP<6>")
	)
	(segment
		(start 350.212152 -78.896464)
		(end 350.08185 -78.479396)
		(width 0.14732)
		(layer "In6.Cu")
		(net "DMI_CPU0_PCH_TX_DP<6>")
	)
	(segment
		(start 370.944648 -212.79485)
		(end 370.944394 -212.794596)
		(width 0.0889)
		(layer "In6.Cu")
		(net "DMI_CPU0_PCH_TX_DP<6>")
	)
	(segment
		(start 350.369124 -62.956948)
		(end 350.682052 -63.269876)
		(width 0.14732)
		(layer "In6.Cu")
		(net "DMI_CPU0_PCH_TX_DP<6>")
	)
	(segment
		(start 383.646426 -147.744688)
		(end 350.554036 -80.401414)
		(width 0.14732)
		(layer "In6.Cu")
		(net "DMI_CPU0_PCH_TX_DP<6>")
	)
	(segment
		(start 350.132142 -79.049372)
		(end 350.212152 -78.896464)
		(width 0.14732)
		(layer "In6.Cu")
		(net "DMI_CPU0_PCH_TX_DP<6>")
	)
	(segment
		(start 369.261136 -217.388694)
		(end 369.252246 -217.383614)
		(width 0.0889)
		(layer "In6.Cu")
		(net "DMI_CPU0_PCH_TX_DP<6>")
	)
	(segment
		(start 365.962946 -227.325682)
		(end 365.971836 -227.320602)
		(width 0.0889)
		(layer "In6.Cu")
		(net "DMI_CPU0_PCH_TX_DP<6>")
	)
	(segment
		(start 348.44228 -70.28434)
		(end 346.833698 -68.675758)
		(width 0.14732)
		(layer "In6.Cu")
		(net "DMI_CPU0_PCH_TX_DP<6>")
	)
	(segment
		(start 369.543584 -216.260426)
		(end 369.543584 -216.25052)
		(width 0.0889)
		(layer "In6.Cu")
		(net "DMI_CPU0_PCH_TX_DP<6>")
	)
	(segment
		(start 371.243352 -208.078324)
		(end 375.943368 -201.365866)
		(width 0.14732)
		(layer "In6.Cu")
		(net "DMI_CPU0_PCH_TX_DP<6>")
	)
	(segment
		(start 367.380774 -223.251776)
		(end 367.381536 -223.251268)
		(width 0.0889)
		(layer "In6.Cu")
		(net "DMI_CPU0_PCH_TX_DP<6>")
	)
	(segment
		(start 370.986304 -209.535776)
		(end 371.243352 -208.078324)
		(width 0.14732)
		(layer "In6.Cu")
		(net "DMI_CPU0_PCH_TX_DP<6>")
	)
	(segment
		(start 349.132398 -71.950326)
		(end 348.44228 -70.28434)
		(width 0.14732)
		(layer "In6.Cu")
		(net "DMI_CPU0_PCH_TX_DP<6>")
	)
	(segment
		(start 349.262446 -76.265024)
		(end 349.132398 -75.84821)
		(width 0.14732)
		(layer "In6.Cu")
		(net "DMI_CPU0_PCH_TX_DP<6>")
	)
	(segment
		(start 366.902746 -224.070164)
		(end 366.916462 -224.06229)
		(width 0.0889)
		(layer "In6.Cu")
		(net "DMI_CPU0_PCH_TX_DP<6>")
	)
	(segment
		(start 366.902746 -225.69805)
		(end 366.911636 -225.69297)
		(width 0.0889)
		(layer "In6.Cu")
		(net "DMI_CPU0_PCH_TX_DP<6>")
	)
	(segment
		(start 370.944394 -211.840318)
		(end 370.986304 -211.798408)
		(width 0.0889)
		(layer "In6.Cu")
		(net "DMI_CPU0_PCH_TX_DP<6>")
	)
	(segment
		(start 375.943368 -201.365866)
		(end 379.787912 -198.673974)
		(width 0.14732)
		(layer "In6.Cu")
		(net "DMI_CPU0_PCH_TX_DP<6>")
	)
	(segment
		(start 368.782346 -219.18676)
		(end 368.791236 -219.18168)
		(width 0.0889)
		(layer "In6.Cu")
		(net "DMI_CPU0_PCH_TX_DP<6>")
	)
	(segment
		(start 368.321082 -219.995496)
		(end 368.321844 -219.994988)
		(width 0.0889)
		(layer "In6.Cu")
		(net "DMI_CPU0_PCH_TX_DP<6>")
	)
	(segment
		(start 379.787912 -198.673974)
		(end 382.009396 -196.45249)
		(width 0.14732)
		(layer "In6.Cu")
		(net "DMI_CPU0_PCH_TX_DP<6>")
	)
	(segment
		(start 365.532416 -228.188012)
		(end 365.556546 -228.098858)
		(width 0.0889)
		(layer "In6.Cu")
		(net "DMI_CPU0_PCH_TX_DP<6>")
	)
	(segment
		(start 370.986304 -211.77631)
		(end 370.986304 -209.535776)
		(width 0.14732)
		(layer "In6.Cu")
		(net "DMI_CPU0_PCH_TX_DP<6>")
	)
	(segment
		(start 349.878904 -77.82941)
		(end 349.748602 -77.412088)
		(width 0.14732)
		(layer "In6.Cu")
		(net "DMI_CPU0_PCH_TX_DP<6>")
	)
	(segment
		(start 370.986304 -211.798408)
		(end 370.986304 -211.77631)
		(width 0.0889)
		(layer "In6.Cu")
		(net "DMI_CPU0_PCH_TX_DP<6>")
	)
	(segment
		(start 367.663984 -222.780098)
		(end 367.663984 -222.761556)
		(width 0.0889)
		(layer "In6.Cu")
		(net "DMI_CPU0_PCH_TX_DP<6>")
	)
	(segment
		(start 389.02386 -178.237134)
		(end 383.646426 -147.744688)
		(width 0.14732)
		(layer "In6.Cu")
		(net "DMI_CPU0_PCH_TX_DP<6>")
	)
	(segment
		(start 349.415354 -76.345034)
		(end 349.262446 -76.265024)
		(width 0.14732)
		(layer "In6.Cu")
		(net "DMI_CPU0_PCH_TX_DP<6>")
	)
	(segment
		(start 366.911636 -224.7138)
		(end 366.902746 -224.70872)
		(width 0.0889)
		(layer "In6.Cu")
		(net "DMI_CPU0_PCH_TX_DP<6>")
	)
	(segment
		(start 369.722146 -215.931242)
		(end 369.731036 -215.926162)
		(width 0.0889)
		(layer "In6.Cu")
		(net "DMI_CPU0_PCH_TX_DP<6>")
	)
	(segment
		(start 349.928942 -78.399132)
		(end 349.798894 -77.982318)
		(width 0.14732)
		(layer "In6.Cu")
		(net "DMI_CPU0_PCH_TX_DP<6>")
	)
	(segment
		(start 366.916462 -224.06229)
		(end 366.917732 -224.061528)
		(width 0.0889)
		(layer "In6.Cu")
		(net "DMI_CPU0_PCH_TX_DP<6>")
	)
	(segment
		(start 370.944394 -212.794596)
		(end 370.944394 -211.840318)
		(width 0.0889)
		(layer "In6.Cu")
		(net "DMI_CPU0_PCH_TX_DP<6>")
	)
	(segment
		(start 369.251992 -218.372944)
		(end 369.266978 -218.364308)
		(width 0.0889)
		(layer "In6.Cu")
		(net "DMI_CPU0_PCH_TX_DP<6>")
	)
	(segment
		(start 349.748602 -77.412088)
		(end 349.595694 -77.332078)
		(width 0.14732)
		(layer "In6.Cu")
		(net "DMI_CPU0_PCH_TX_DP<6>")
	)
	(segment
		(start 366.442244 -226.506278)
		(end 366.447578 -226.50323)
		(width 0.0889)
		(layer "In6.Cu")
		(net "DMI_CPU0_PCH_TX_DP<6>")
	)
	(segment
		(start 382.009396 -196.45249)
		(end 387.092952 -189.192154)
		(width 0.14732)
		(layer "In6.Cu")
		(net "DMI_CPU0_PCH_TX_DP<6>")
	)
	(segment
		(start 370.013484 -215.435688)
		(end 370.012976 -215.436704)
		(width 0.0889)
		(layer "In6.Cu")
		(net "DMI_CPU0_PCH_TX_DP<6>")
	)
	(segment
		(start 370.317776 -215.022176)
		(end 370.944648 -214.395304)
		(width 0.0889)
		(layer "In6.Cu")
		(net "DMI_CPU0_PCH_TX_DP<6>")
	)
	(segment
		(start 349.465646 -76.915264)
		(end 349.545656 -76.762356)
		(width 0.14732)
		(layer "In6.Cu")
		(net "DMI_CPU0_PCH_TX_DP<6>")
	)
	(segment
		(start 346.833698 -68.675758)
		(end 346.833698 -65.316862)
		(width 0.14732)
		(layer "In6.Cu")
		(net "DMI_CPU0_PCH_TX_DP<6>")
	)
	(segment
		(start 368.321844 -219.994988)
		(end 368.327178 -219.99194)
		(width 0.0889)
		(layer "In6.Cu")
		(net "DMI_CPU0_PCH_TX_DP<6>")
	)
	(arc
		(start 365.971836 -227.320602)
		(mid 366.176171 -227.117997)
		(end 366.254284 -226.84105)
		(width 0.0889)
		(layer "In6.Cu")
		(net "DMI_CPU0_PCH_TX_DP<6>")
	)
	(arc
		(start 368.133884 -220.311218)
		(mid 368.186154 -220.128853)
		(end 368.321082 -219.995496)
		(width 0.0889)
		(layer "In6.Cu")
		(net "DMI_CPU0_PCH_TX_DP<6>")
	)
	(arc
		(start 365.573564 -228.08565)
		(mid 365.725995 -227.895668)
		(end 365.784384 -227.659184)
		(width 0.0889)
		(layer "In6.Cu")
		(net "DMI_CPU0_PCH_TX_DP<6>")
	)
	(arc
		(start 369.266978 -218.364308)
		(mid 369.54376 -217.874797)
		(end 369.261136 -217.388694)
		(width 0.0889)
		(layer "In6.Cu")
		(net "DMI_CPU0_PCH_TX_DP<6>")
	)
	(arc
		(start 366.917732 -224.061528)
		(mid 367.120145 -223.855115)
		(end 367.194084 -223.575626)
		(width 0.0889)
		(layer "In6.Cu")
		(net "DMI_CPU0_PCH_TX_DP<6>")
	)
	(arc
		(start 367.851436 -222.437198)
		(mid 368.055771 -222.234593)
		(end 368.133884 -221.957646)
		(width 0.0889)
		(layer "In6.Cu")
		(net "DMI_CPU0_PCH_TX_DP<6>")
	)
	(arc
		(start 369.252246 -217.383614)
		(mid 369.073649 -217.064336)
		(end 369.252246 -216.745058)
		(width 0.0889)
		(layer "In6.Cu")
		(net "DMI_CPU0_PCH_TX_DP<6>")
	)
	(arc
		(start 366.724184 -226.017328)
		(mid 366.724236 -226.009961)
		(end 366.724438 -226.002596)
		(width 0.0889)
		(layer "In6.Cu")
		(net "DMI_CPU0_PCH_TX_DP<6>")
	)
	(arc
		(start 369.261136 -216.739978)
		(mid 369.465471 -216.537373)
		(end 369.543584 -216.260426)
		(width 0.0889)
		(layer "In6.Cu")
		(net "DMI_CPU0_PCH_TX_DP<6>")
	)
	(arc
		(start 367.194084 -223.575626)
		(mid 367.241763 -223.392726)
		(end 367.372646 -223.256348)
		(width 0.0889)
		(layer "In6.Cu")
		(net "DMI_CPU0_PCH_TX_DP<6>")
	)
	(arc
		(start 366.911636 -225.69297)
		(mid 367.112918 -225.495483)
		(end 367.19383 -225.225356)
		(width 0.0889)
		(layer "In6.Cu")
		(net "DMI_CPU0_PCH_TX_DP<6>")
	)
	(arc
		(start 366.902746 -224.70872)
		(mid 366.72427 -224.389442)
		(end 366.902746 -224.070164)
		(width 0.0889)
		(layer "In6.Cu")
		(net "DMI_CPU0_PCH_TX_DP<6>")
	)
	(arc
		(start 368.603784 -219.506038)
		(mid 368.651463 -219.323138)
		(end 368.782346 -219.18676)
		(width 0.0889)
		(layer "In6.Cu")
		(net "DMI_CPU0_PCH_TX_DP<6>")
	)
	(arc
		(start 370.200936 -215.111838)
		(mid 370.262282 -215.070821)
		(end 370.317776 -215.022176)
		(width 0.0889)
		(layer "In6.Cu")
		(net "DMI_CPU0_PCH_TX_DP<6>")
	)
	(arc
		(start 370.012976 -215.436704)
		(mid 370.061745 -215.251868)
		(end 370.195348 -215.11514)
		(width 0.0889)
		(layer "In6.Cu")
		(net "DMI_CPU0_PCH_TX_DP<6>")
	)
	(arc
		(start 368.133884 -221.939104)
		(mid 368.186154 -221.756739)
		(end 368.321082 -221.623382)
		(width 0.0889)
		(layer "In6.Cu")
		(net "DMI_CPU0_PCH_TX_DP<6>")
	)
	(arc
		(start 366.447578 -226.50323)
		(mid 366.650165 -226.296879)
		(end 366.724184 -226.017328)
		(width 0.0889)
		(layer "In6.Cu")
		(net "DMI_CPU0_PCH_TX_DP<6>")
	)
	(arc
		(start 366.724438 -226.002596)
		(mid 366.775492 -225.828016)
		(end 366.902746 -225.69805)
		(width 0.0889)
		(layer "In6.Cu")
		(net "DMI_CPU0_PCH_TX_DP<6>")
	)
	(arc
		(start 368.333274 -221.61627)
		(mid 368.603685 -221.126803)
		(end 368.321082 -220.644212)
		(width 0.0889)
		(layer "In6.Cu")
		(net "DMI_CPU0_PCH_TX_DP<6>")
	)
	(arc
		(start 365.784384 -227.64496)
		(mid 365.832063 -227.46206)
		(end 365.962946 -227.325682)
		(width 0.0889)
		(layer "In6.Cu")
		(net "DMI_CPU0_PCH_TX_DP<6>")
	)
	(arc
		(start 368.321082 -220.644212)
		(mid 368.186149 -220.510858)
		(end 368.133884 -220.32849)
		(width 0.0889)
		(layer "In6.Cu")
		(net "DMI_CPU0_PCH_TX_DP<6>")
	)
	(arc
		(start 367.19383 -225.187764)
		(mid 367.11446 -224.91403)
		(end 366.911636 -224.7138)
		(width 0.0889)
		(layer "In6.Cu")
		(net "DMI_CPU0_PCH_TX_DP<6>")
	)
	(arc
		(start 367.381536 -223.251268)
		(mid 367.583822 -223.052287)
		(end 367.663984 -222.780098)
		(width 0.0889)
		(layer "In6.Cu")
		(net "DMI_CPU0_PCH_TX_DP<6>")
	)
	(arc
		(start 369.543584 -216.25052)
		(mid 369.591263 -216.06762)
		(end 369.722146 -215.931242)
		(width 0.0889)
		(layer "In6.Cu")
		(net "DMI_CPU0_PCH_TX_DP<6>")
	)
	(arc
		(start 368.791236 -219.18168)
		(mid 368.994059 -218.981449)
		(end 369.07343 -218.707716)
		(width 0.0889)
		(layer "In6.Cu")
		(net "DMI_CPU0_PCH_TX_DP<6>")
	)
	(arc
		(start 368.327178 -219.99194)
		(mid 368.529765 -219.785589)
		(end 368.603784 -219.506038)
		(width 0.0889)
		(layer "In6.Cu")
		(net "DMI_CPU0_PCH_TX_DP<6>")
	)
	(arc
		(start 367.663984 -222.761556)
		(mid 367.711663 -222.578656)
		(end 367.842546 -222.442278)
		(width 0.0889)
		(layer "In6.Cu")
		(net "DMI_CPU0_PCH_TX_DP<6>")
	)
	(arc
		(start 369.07343 -218.692222)
		(mid 369.121109 -218.509322)
		(end 369.251992 -218.372944)
		(width 0.0889)
		(layer "In6.Cu")
		(net "DMI_CPU0_PCH_TX_DP<6>")
	)
	(arc
		(start 366.254284 -226.822508)
		(mid 366.306554 -226.640143)
		(end 366.441482 -226.506786)
		(width 0.0889)
		(layer "In6.Cu")
		(net "DMI_CPU0_PCH_TX_DP<6>")
	)
	(arc
		(start 369.731036 -215.926162)
		(mid 369.935371 -215.723557)
		(end 370.013484 -215.44661)
		(width 0.0889)
		(layer "In6.Cu")
		(net "DMI_CPU0_PCH_TX_DP<6>")
	)
	(arc
		(start 365.556546 -228.098858)
		(mid 365.565118 -228.092335)
		(end 365.573564 -228.08565)
		(width 0.0889)
		(layer "In6.Cu")
		(net "DMI_CPU0_PCH_TX_DP<6>")
	)
	(segment
		(start 352.26879 -65.028572)
		(end 352.442526 -65.028572)
		(width 0.13208)
		(layer "F.Cu")
		(net "DMI_CPU0_PCH_TX_DP<5>")
	)
	(segment
		(start 352.442526 -65.028572)
		(end 352.743516 -65.329562)
		(width 0.13208)
		(layer "F.Cu")
		(net "DMI_CPU0_PCH_TX_DP<5>")
	)
	(segment
		(start 364.279434 -228.180646)
		(end 364.279434 -227.64496)
		(width 0.13208)
		(layer "F.Cu")
		(net "DMI_CPU0_PCH_TX_DP<5>")
	)
	(segment
		(start 364.27918 -228.1809)
		(end 364.279434 -228.180646)
		(width 0.13208)
		(layer "F.Cu")
		(net "DMI_CPU0_PCH_TX_DP<5>")
	)
	(segment
		(start 351.9424 -65.354962)
		(end 352.26879 -65.028572)
		(width 0.13208)
		(layer "F.Cu")
		(net "DMI_CPU0_PCH_TX_DP<5>")
	)
	(segment
		(start 350.068134 -69.738748)
		(end 349.901002 -69.334888)
		(width 0.14732)
		(layer "In6.Cu")
		(net "DMI_CPU0_PCH_TX_DP<5>")
	)
	(segment
		(start 351.153984 -65.20307)
		(end 351.56013 -65.034922)
		(width 0.14732)
		(layer "In6.Cu")
		(net "DMI_CPU0_PCH_TX_DP<5>")
	)
	(segment
		(start 372.821962 -212.251798)
		(end 372.864126 -212.209634)
		(width 0.0889)
		(layer "In6.Cu")
		(net "DMI_CPU0_PCH_TX_DP<5>")
	)
	(segment
		(start 380.850902 -200.095104)
		(end 384.24358 -196.702426)
		(width 0.14732)
		(layer "In6.Cu")
		(net "DMI_CPU0_PCH_TX_DP<5>")
	)
	(segment
		(start 388.049262 -192.080134)
		(end 388.871968 -190.905384)
		(width 0.14732)
		(layer "In6.Cu")
		(net "DMI_CPU0_PCH_TX_DP<5>")
	)
	(segment
		(start 372.864126 -212.187536)
		(end 372.864126 -211.229194)
		(width 0.14732)
		(layer "In6.Cu")
		(net "DMI_CPU0_PCH_TX_DP<5>")
	)
	(segment
		(start 369.07343 -225.225356)
		(end 369.07343 -225.187764)
		(width 0.0889)
		(layer "In6.Cu")
		(net "DMI_CPU0_PCH_TX_DP<5>")
	)
	(segment
		(start 367.663984 -227.659184)
		(end 367.663984 -227.64496)
		(width 0.0889)
		(layer "In6.Cu")
		(net "DMI_CPU0_PCH_TX_DP<5>")
	)
	(segment
		(start 370.200682 -221.623382)
		(end 370.201444 -221.622874)
		(width 0.0889)
		(layer "In6.Cu")
		(net "DMI_CPU0_PCH_TX_DP<5>")
	)
	(segment
		(start 350.82226 -71.241412)
		(end 350.655128 -70.837552)
		(width 0.14732)
		(layer "In6.Cu")
		(net "DMI_CPU0_PCH_TX_DP<5>")
	)
	(segment
		(start 370.199158 -221.624144)
		(end 370.200682 -221.623382)
		(width 0.0889)
		(layer "In6.Cu")
		(net "DMI_CPU0_PCH_TX_DP<5>")
	)
	(segment
		(start 371.139974 -216.740486)
		(end 371.140736 -216.739978)
		(width 0.0889)
		(layer "In6.Cu")
		(net "DMI_CPU0_PCH_TX_DP<5>")
	)
	(segment
		(start 368.321844 -226.506278)
		(end 368.327178 -226.50323)
		(width 0.0889)
		(layer "In6.Cu")
		(net "DMI_CPU0_PCH_TX_DP<5>")
	)
	(segment
		(start 371.131846 -216.745058)
		(end 371.137942 -216.741502)
		(width 0.0889)
		(layer "In6.Cu")
		(net "DMI_CPU0_PCH_TX_DP<5>")
	)
	(segment
		(start 351.05594 -72.124062)
		(end 351.055686 -72.124062)
		(width 0.14732)
		(layer "In6.Cu")
		(net "DMI_CPU0_PCH_TX_DP<5>")
	)
	(segment
		(start 350.655128 -70.837552)
		(end 350.495616 -70.771512)
		(width 0.14732)
		(layer "In6.Cu")
		(net "DMI_CPU0_PCH_TX_DP<5>")
	)
	(segment
		(start 372.821962 -214.39759)
		(end 372.821962 -212.251798)
		(width 0.0889)
		(layer "In6.Cu")
		(net "DMI_CPU0_PCH_TX_DP<5>")
	)
	(segment
		(start 350.328738 -70.367906)
		(end 350.394778 -70.208648)
		(width 0.14732)
		(layer "In6.Cu")
		(net "DMI_CPU0_PCH_TX_DP<5>")
	)
	(segment
		(start 348.57944 -66.198242)
		(end 349.574612 -65.20307)
		(width 0.14732)
		(layer "In6.Cu")
		(net "DMI_CPU0_PCH_TX_DP<5>")
	)
	(segment
		(start 348.57944 -68.013326)
		(end 348.57944 -66.198242)
		(width 0.14732)
		(layer "In6.Cu")
		(net "DMI_CPU0_PCH_TX_DP<5>")
	)
	(segment
		(start 370.013484 -220.32849)
		(end 370.013484 -220.311218)
		(width 0.0889)
		(layer "In6.Cu")
		(net "DMI_CPU0_PCH_TX_DP<5>")
	)
	(segment
		(start 372.197376 -215.022176)
		(end 372.821962 -214.39759)
		(width 0.0889)
		(layer "In6.Cu")
		(net "DMI_CPU0_PCH_TX_DP<5>")
	)
	(segment
		(start 369.722146 -222.442278)
		(end 369.731036 -222.437198)
		(width 0.0889)
		(layer "In6.Cu")
		(net "DMI_CPU0_PCH_TX_DP<5>")
	)
	(segment
		(start 350.394778 -70.208648)
		(end 350.227646 -69.804788)
		(width 0.14732)
		(layer "In6.Cu")
		(net "DMI_CPU0_PCH_TX_DP<5>")
	)
	(segment
		(start 369.252246 -223.256348)
		(end 369.261136 -223.251268)
		(width 0.0889)
		(layer "In6.Cu")
		(net "DMI_CPU0_PCH_TX_DP<5>")
	)
	(segment
		(start 371.131592 -218.372944)
		(end 371.146578 -218.364308)
		(width 0.0889)
		(layer "In6.Cu")
		(net "DMI_CPU0_PCH_TX_DP<5>")
	)
	(segment
		(start 370.95303 -218.707716)
		(end 370.95303 -218.692222)
		(width 0.0889)
		(layer "In6.Cu")
		(net "DMI_CPU0_PCH_TX_DP<5>")
	)
	(segment
		(start 384.24358 -196.702426)
		(end 386.932424 -192.8622)
		(width 0.14732)
		(layer "In6.Cu")
		(net "DMI_CPU0_PCH_TX_DP<5>")
	)
	(segment
		(start 388.90702 -190.8556)
		(end 390.997948 -178.997864)
		(width 0.14732)
		(layer "In6.Cu")
		(net "DMI_CPU0_PCH_TX_DP<5>")
	)
	(segment
		(start 367.842546 -227.325682)
		(end 367.851436 -227.320602)
		(width 0.0889)
		(layer "In6.Cu")
		(net "DMI_CPU0_PCH_TX_DP<5>")
	)
	(segment
		(start 386.932424 -192.8622)
		(end 388.049262 -192.080134)
		(width 0.14732)
		(layer "In6.Cu")
		(net "DMI_CPU0_PCH_TX_DP<5>")
	)
	(segment
		(start 372.074948 -215.11514)
		(end 372.081044 -215.111584)
		(width 0.0889)
		(layer "In6.Cu")
		(net "DMI_CPU0_PCH_TX_DP<5>")
	)
	(segment
		(start 350.227646 -69.804788)
		(end 350.068134 -69.738748)
		(width 0.14732)
		(layer "In6.Cu")
		(net "DMI_CPU0_PCH_TX_DP<5>")
	)
	(segment
		(start 368.782346 -224.070164)
		(end 368.793522 -224.063814)
		(width 0.0889)
		(layer "In6.Cu")
		(net "DMI_CPU0_PCH_TX_DP<5>")
	)
	(segment
		(start 351.055686 -72.124062)
		(end 350.75622 -71.40067)
		(width 0.14732)
		(layer "In6.Cu")
		(net "DMI_CPU0_PCH_TX_DP<5>")
	)
	(segment
		(start 371.893084 -215.44661)
		(end 371.893084 -215.435688)
		(width 0.0889)
		(layer "In6.Cu")
		(net "DMI_CPU0_PCH_TX_DP<5>")
	)
	(segment
		(start 364.279434 -227.64496)
		(end 364.435898 -227.373942)
		(width 0.0889)
		(layer "In6.Cu")
		(net "DMI_CPU0_PCH_TX_DP<5>")
	)
	(segment
		(start 370.204492 -219.99321)
		(end 370.206778 -219.99194)
		(width 0.0889)
		(layer "In6.Cu")
		(net "DMI_CPU0_PCH_TX_DP<5>")
	)
	(segment
		(start 368.791236 -224.7138)
		(end 368.782346 -224.70872)
		(width 0.0889)
		(layer "In6.Cu")
		(net "DMI_CPU0_PCH_TX_DP<5>")
	)
	(segment
		(start 390.997948 -178.997864)
		(end 385.172458 -145.956782)
		(width 0.14732)
		(layer "In6.Cu")
		(net "DMI_CPU0_PCH_TX_DP<5>")
	)
	(segment
		(start 368.782346 -225.69805)
		(end 368.79022 -225.693478)
		(width 0.0889)
		(layer "In6.Cu")
		(net "DMI_CPU0_PCH_TX_DP<5>")
	)
	(segment
		(start 370.191792 -221.628462)
		(end 370.199158 -221.624144)
		(width 0.0889)
		(layer "In6.Cu")
		(net "DMI_CPU0_PCH_TX_DP<5>")
	)
	(segment
		(start 371.423184 -216.260426)
		(end 371.423184 -216.25052)
		(width 0.0889)
		(layer "In6.Cu")
		(net "DMI_CPU0_PCH_TX_DP<5>")
	)
	(segment
		(start 388.871968 -190.905384)
		(end 388.872222 -190.905384)
		(width 0.14732)
		(layer "In6.Cu")
		(net "DMI_CPU0_PCH_TX_DP<5>")
	)
	(segment
		(start 352.448876 -65.034922)
		(end 352.743516 -65.329562)
		(width 0.14732)
		(layer "In6.Cu")
		(net "DMI_CPU0_PCH_TX_DP<5>")
	)
	(segment
		(start 364.654084 -227.64496)
		(end 364.654084 -227.667058)
		(width 0.0889)
		(layer "In6.Cu")
		(net "DMI_CPU0_PCH_TX_DP<5>")
	)
	(segment
		(start 372.863872 -209.700622)
		(end 373.045228 -208.672176)
		(width 0.14732)
		(layer "In6.Cu")
		(net "DMI_CPU0_PCH_TX_DP<5>")
	)
	(segment
		(start 370.661946 -219.18676)
		(end 370.670836 -219.18168)
		(width 0.0889)
		(layer "In6.Cu")
		(net "DMI_CPU0_PCH_TX_DP<5>")
	)
	(segment
		(start 351.56013 -65.034922)
		(end 352.448876 -65.034922)
		(width 0.14732)
		(layer "In6.Cu")
		(net "DMI_CPU0_PCH_TX_DP<5>")
	)
	(segment
		(start 368.793522 -224.063814)
		(end 368.797332 -224.061528)
		(width 0.0889)
		(layer "In6.Cu")
		(net "DMI_CPU0_PCH_TX_DP<5>")
	)
	(segment
		(start 369.543584 -222.780098)
		(end 369.543584 -222.761556)
		(width 0.0889)
		(layer "In6.Cu")
		(net "DMI_CPU0_PCH_TX_DP<5>")
	)
	(segment
		(start 350.75622 -71.40067)
		(end 350.82226 -71.241412)
		(width 0.14732)
		(layer "In6.Cu")
		(net "DMI_CPU0_PCH_TX_DP<5>")
	)
	(segment
		(start 372.864126 -212.209634)
		(end 372.864126 -212.187536)
		(width 0.0889)
		(layer "In6.Cu")
		(net "DMI_CPU0_PCH_TX_DP<5>")
	)
	(segment
		(start 370.01323 -221.963234)
		(end 370.01323 -221.94774)
		(width 0.0889)
		(layer "In6.Cu")
		(net "DMI_CPU0_PCH_TX_DP<5>")
	)
	(segment
		(start 371.601746 -215.931242)
		(end 371.610636 -215.926162)
		(width 0.0889)
		(layer "In6.Cu")
		(net "DMI_CPU0_PCH_TX_DP<5>")
	)
	(segment
		(start 377.320302 -202.566778)
		(end 380.850902 -200.095104)
		(width 0.14732)
		(layer "In6.Cu")
		(net "DMI_CPU0_PCH_TX_DP<5>")
	)
	(segment
		(start 350.495616 -70.771512)
		(end 350.328738 -70.367906)
		(width 0.14732)
		(layer "In6.Cu")
		(net "DMI_CPU0_PCH_TX_DP<5>")
	)
	(segment
		(start 388.872222 -190.905384)
		(end 388.90702 -190.8556)
		(width 0.14732)
		(layer "In6.Cu")
		(net "DMI_CPU0_PCH_TX_DP<5>")
	)
	(segment
		(start 352.81616 -79.734664)
		(end 351.05594 -72.124062)
		(width 0.14732)
		(layer "In6.Cu")
		(net "DMI_CPU0_PCH_TX_DP<5>")
	)
	(segment
		(start 368.133884 -226.84105)
		(end 368.133884 -226.822508)
		(width 0.0889)
		(layer "In6.Cu")
		(net "DMI_CPU0_PCH_TX_DP<5>")
	)
	(segment
		(start 368.321082 -226.506786)
		(end 368.321844 -226.506278)
		(width 0.0889)
		(layer "In6.Cu")
		(net "DMI_CPU0_PCH_TX_DP<5>")
	)
	(segment
		(start 364.435898 -227.373942)
		(end 364.51413 -227.353114)
		(width 0.0889)
		(layer "In6.Cu")
		(net "DMI_CPU0_PCH_TX_DP<5>")
	)
	(segment
		(start 368.79022 -225.693478)
		(end 368.791236 -225.69297)
		(width 0.0889)
		(layer "In6.Cu")
		(net "DMI_CPU0_PCH_TX_DP<5>")
	)
	(segment
		(start 385.172458 -145.956782)
		(end 352.81616 -79.734664)
		(width 0.14732)
		(layer "In6.Cu")
		(net "DMI_CPU0_PCH_TX_DP<5>")
	)
	(segment
		(start 349.901002 -69.334888)
		(end 348.57944 -68.013326)
		(width 0.14732)
		(layer "In6.Cu")
		(net "DMI_CPU0_PCH_TX_DP<5>")
	)
	(segment
		(start 371.893084 -215.435688)
		(end 371.892576 -215.436704)
		(width 0.0889)
		(layer "In6.Cu")
		(net "DMI_CPU0_PCH_TX_DP<5>")
	)
	(segment
		(start 370.200682 -219.995496)
		(end 370.204492 -219.99321)
		(width 0.0889)
		(layer "In6.Cu")
		(net "DMI_CPU0_PCH_TX_DP<5>")
	)
	(segment
		(start 370.201444 -221.622874)
		(end 370.206778 -221.619826)
		(width 0.0889)
		(layer "In6.Cu")
		(net "DMI_CPU0_PCH_TX_DP<5>")
	)
	(segment
		(start 349.574612 -65.20307)
		(end 351.153984 -65.20307)
		(width 0.14732)
		(layer "In6.Cu")
		(net "DMI_CPU0_PCH_TX_DP<5>")
	)
	(segment
		(start 373.045228 -208.672176)
		(end 377.320302 -202.566778)
		(width 0.14732)
		(layer "In6.Cu")
		(net "DMI_CPU0_PCH_TX_DP<5>")
	)
	(segment
		(start 372.863872 -211.22894)
		(end 372.863872 -209.700622)
		(width 0.14732)
		(layer "In6.Cu")
		(net "DMI_CPU0_PCH_TX_DP<5>")
	)
	(segment
		(start 366.25403 -228.474524)
		(end 366.25403 -228.45903)
		(width 0.0889)
		(layer "In6.Cu")
		(net "DMI_CPU0_PCH_TX_DP<5>")
	)
	(segment
		(start 371.140736 -217.388694)
		(end 371.131846 -217.383614)
		(width 0.0889)
		(layer "In6.Cu")
		(net "DMI_CPU0_PCH_TX_DP<5>")
	)
	(segment
		(start 364.936278 -228.134672)
		(end 364.945168 -228.139752)
		(width 0.0889)
		(layer "In6.Cu")
		(net "DMI_CPU0_PCH_TX_DP<5>")
	)
	(segment
		(start 372.864126 -211.229194)
		(end 372.863872 -211.22894)
		(width 0.14732)
		(layer "In6.Cu")
		(net "DMI_CPU0_PCH_TX_DP<5>")
	)
	(segment
		(start 371.137942 -216.741502)
		(end 371.139974 -216.740486)
		(width 0.0889)
		(layer "In6.Cu")
		(net "DMI_CPU0_PCH_TX_DP<5>")
	)
	(arc
		(start 369.731036 -222.437198)
		(mid 369.933859 -222.236967)
		(end 370.01323 -221.963234)
		(width 0.0889)
		(layer "In6.Cu")
		(net "DMI_CPU0_PCH_TX_DP<5>")
	)
	(arc
		(start 368.791236 -225.69297)
		(mid 368.992518 -225.495483)
		(end 369.07343 -225.225356)
		(width 0.0889)
		(layer "In6.Cu")
		(net "DMI_CPU0_PCH_TX_DP<5>")
	)
	(arc
		(start 367.851436 -227.320602)
		(mid 368.055771 -227.117997)
		(end 368.133884 -226.84105)
		(width 0.0889)
		(layer "In6.Cu")
		(net "DMI_CPU0_PCH_TX_DP<5>")
	)
	(arc
		(start 368.782346 -224.70872)
		(mid 368.60387 -224.389442)
		(end 368.782346 -224.070164)
		(width 0.0889)
		(layer "In6.Cu")
		(net "DMI_CPU0_PCH_TX_DP<5>")
	)
	(arc
		(start 371.146578 -218.364308)
		(mid 371.42336 -217.874797)
		(end 371.140736 -217.388694)
		(width 0.0889)
		(layer "In6.Cu")
		(net "DMI_CPU0_PCH_TX_DP<5>")
	)
	(arc
		(start 370.206778 -221.619826)
		(mid 370.483341 -221.130332)
		(end 370.200682 -220.644212)
		(width 0.0889)
		(layer "In6.Cu")
		(net "DMI_CPU0_PCH_TX_DP<5>")
	)
	(arc
		(start 368.604038 -226.002596)
		(mid 368.655092 -225.828016)
		(end 368.782346 -225.69805)
		(width 0.0889)
		(layer "In6.Cu")
		(net "DMI_CPU0_PCH_TX_DP<5>")
	)
	(arc
		(start 370.200682 -220.644212)
		(mid 370.065749 -220.510858)
		(end 370.013484 -220.32849)
		(width 0.0889)
		(layer "In6.Cu")
		(net "DMI_CPU0_PCH_TX_DP<5>")
	)
	(arc
		(start 366.815878 -228.134672)
		(mid 367.375304 -228.138365)
		(end 367.663984 -227.659184)
		(width 0.0889)
		(layer "In6.Cu")
		(net "DMI_CPU0_PCH_TX_DP<5>")
	)
	(arc
		(start 365.12373 -228.45903)
		(mid 365.681135 -229.024127)
		(end 366.25403 -228.474524)
		(width 0.0889)
		(layer "In6.Cu")
		(net "DMI_CPU0_PCH_TX_DP<5>")
	)
	(arc
		(start 370.95303 -218.692222)
		(mid 371.000709 -218.509322)
		(end 371.131592 -218.372944)
		(width 0.0889)
		(layer "In6.Cu")
		(net "DMI_CPU0_PCH_TX_DP<5>")
	)
	(arc
		(start 364.945168 -228.139752)
		(mid 365.072422 -228.269718)
		(end 365.123476 -228.444298)
		(width 0.0889)
		(layer "In6.Cu")
		(net "DMI_CPU0_PCH_TX_DP<5>")
	)
	(arc
		(start 371.610636 -215.926162)
		(mid 371.814971 -215.723557)
		(end 371.893084 -215.44661)
		(width 0.0889)
		(layer "In6.Cu")
		(net "DMI_CPU0_PCH_TX_DP<5>")
	)
	(arc
		(start 364.51413 -227.353114)
		(mid 364.617275 -227.483139)
		(end 364.654084 -227.64496)
		(width 0.0889)
		(layer "In6.Cu")
		(net "DMI_CPU0_PCH_TX_DP<5>")
	)
	(arc
		(start 366.25403 -228.45903)
		(mid 366.441329 -228.134589)
		(end 366.815878 -228.134672)
		(width 0.0889)
		(layer "In6.Cu")
		(net "DMI_CPU0_PCH_TX_DP<5>")
	)
	(arc
		(start 371.423184 -216.25052)
		(mid 371.470863 -216.06762)
		(end 371.601746 -215.931242)
		(width 0.0889)
		(layer "In6.Cu")
		(net "DMI_CPU0_PCH_TX_DP<5>")
	)
	(arc
		(start 368.133884 -226.822508)
		(mid 368.186154 -226.640143)
		(end 368.321082 -226.506786)
		(width 0.0889)
		(layer "In6.Cu")
		(net "DMI_CPU0_PCH_TX_DP<5>")
	)
	(arc
		(start 364.654084 -227.667058)
		(mid 364.734995 -227.937186)
		(end 364.936278 -228.134672)
		(width 0.0889)
		(layer "In6.Cu")
		(net "DMI_CPU0_PCH_TX_DP<5>")
	)
	(arc
		(start 368.603784 -226.017328)
		(mid 368.603836 -226.009961)
		(end 368.604038 -226.002596)
		(width 0.0889)
		(layer "In6.Cu")
		(net "DMI_CPU0_PCH_TX_DP<5>")
	)
	(arc
		(start 370.01323 -221.94774)
		(mid 370.060909 -221.76484)
		(end 370.191792 -221.628462)
		(width 0.0889)
		(layer "In6.Cu")
		(net "DMI_CPU0_PCH_TX_DP<5>")
	)
	(arc
		(start 370.483384 -219.506038)
		(mid 370.531063 -219.323138)
		(end 370.661946 -219.18676)
		(width 0.0889)
		(layer "In6.Cu")
		(net "DMI_CPU0_PCH_TX_DP<5>")
	)
	(arc
		(start 371.140736 -216.739978)
		(mid 371.345071 -216.537373)
		(end 371.423184 -216.260426)
		(width 0.0889)
		(layer "In6.Cu")
		(net "DMI_CPU0_PCH_TX_DP<5>")
	)
	(arc
		(start 369.073684 -223.575626)
		(mid 369.121363 -223.392726)
		(end 369.252246 -223.256348)
		(width 0.0889)
		(layer "In6.Cu")
		(net "DMI_CPU0_PCH_TX_DP<5>")
	)
	(arc
		(start 365.123476 -228.444298)
		(mid 365.123673 -228.451663)
		(end 365.12373 -228.45903)
		(width 0.0889)
		(layer "In6.Cu")
		(net "DMI_CPU0_PCH_TX_DP<5>")
	)
	(arc
		(start 368.797332 -224.061528)
		(mid 368.999745 -223.855115)
		(end 369.073684 -223.575626)
		(width 0.0889)
		(layer "In6.Cu")
		(net "DMI_CPU0_PCH_TX_DP<5>")
	)
	(arc
		(start 372.081044 -215.111584)
		(mid 372.142128 -215.070676)
		(end 372.197376 -215.022176)
		(width 0.0889)
		(layer "In6.Cu")
		(net "DMI_CPU0_PCH_TX_DP<5>")
	)
	(arc
		(start 367.663984 -227.64496)
		(mid 367.711663 -227.46206)
		(end 367.842546 -227.325682)
		(width 0.0889)
		(layer "In6.Cu")
		(net "DMI_CPU0_PCH_TX_DP<5>")
	)
	(arc
		(start 370.670836 -219.18168)
		(mid 370.873659 -218.981449)
		(end 370.95303 -218.707716)
		(width 0.0889)
		(layer "In6.Cu")
		(net "DMI_CPU0_PCH_TX_DP<5>")
	)
	(arc
		(start 369.543584 -222.761556)
		(mid 369.591263 -222.578656)
		(end 369.722146 -222.442278)
		(width 0.0889)
		(layer "In6.Cu")
		(net "DMI_CPU0_PCH_TX_DP<5>")
	)
	(arc
		(start 371.131846 -217.383614)
		(mid 370.953249 -217.064336)
		(end 371.131846 -216.745058)
		(width 0.0889)
		(layer "In6.Cu")
		(net "DMI_CPU0_PCH_TX_DP<5>")
	)
	(arc
		(start 369.07343 -225.187764)
		(mid 368.99406 -224.91403)
		(end 368.791236 -224.7138)
		(width 0.0889)
		(layer "In6.Cu")
		(net "DMI_CPU0_PCH_TX_DP<5>")
	)
	(arc
		(start 371.892576 -215.436704)
		(mid 371.941345 -215.251868)
		(end 372.074948 -215.11514)
		(width 0.0889)
		(layer "In6.Cu")
		(net "DMI_CPU0_PCH_TX_DP<5>")
	)
	(arc
		(start 370.206778 -219.99194)
		(mid 370.409365 -219.785589)
		(end 370.483384 -219.506038)
		(width 0.0889)
		(layer "In6.Cu")
		(net "DMI_CPU0_PCH_TX_DP<5>")
	)
	(arc
		(start 369.261136 -223.251268)
		(mid 369.463422 -223.052287)
		(end 369.543584 -222.780098)
		(width 0.0889)
		(layer "In6.Cu")
		(net "DMI_CPU0_PCH_TX_DP<5>")
	)
	(arc
		(start 368.327178 -226.50323)
		(mid 368.529765 -226.296879)
		(end 368.603784 -226.017328)
		(width 0.0889)
		(layer "In6.Cu")
		(net "DMI_CPU0_PCH_TX_DP<5>")
	)
	(arc
		(start 370.013484 -220.311218)
		(mid 370.065754 -220.128853)
		(end 370.200682 -219.995496)
		(width 0.0889)
		(layer "In6.Cu")
		(net "DMI_CPU0_PCH_TX_DP<5>")
	)
	(segment
		(start 349.570548 -66.662554)
		(end 350.351598 -66.662554)
		(width 0.13208)
		(layer "F.Cu")
		(net "DMI_CPU0_PCH_TX_DP<4>")
	)
	(segment
		(start 363.80928 -228.994716)
		(end 363.80928 -228.45903)
		(width 0.13208)
		(layer "F.Cu")
		(net "DMI_CPU0_PCH_TX_DP<4>")
	)
	(segment
		(start 363.809534 -228.99497)
		(end 363.80928 -228.994716)
		(width 0.13208)
		(layer "F.Cu")
		(net "DMI_CPU0_PCH_TX_DP<4>")
	)
	(segment
		(start 349.228664 -66.988944)
		(end 349.570548 -66.662554)
		(width 0.13208)
		(layer "F.Cu")
		(net "DMI_CPU0_PCH_TX_DP<4>")
	)
	(segment
		(start 350.351598 -66.662554)
		(end 350.652588 -66.963544)
		(width 0.13208)
		(layer "F.Cu")
		(net "DMI_CPU0_PCH_TX_DP<4>")
	)
	(segment
		(start 364.463838 -228.946964)
		(end 364.466632 -228.948488)
		(width 0.0889)
		(layer "In6.Cu")
		(net "DMI_CPU0_PCH_TX_DP<4>")
	)
	(segment
		(start 352.194876 -72.150732)
		(end 352.048318 -72.0598)
		(width 0.14732)
		(layer "In6.Cu")
		(net "DMI_CPU0_PCH_TX_DP<4>")
	)
	(segment
		(start 350.41713 -68.46951)
		(end 350.107758 -68.160138)
		(width 0.14732)
		(layer "In6.Cu")
		(net "DMI_CPU0_PCH_TX_DP<4>")
	)
	(segment
		(start 363.80928 -228.45903)
		(end 363.652816 -228.188012)
		(width 0.0889)
		(layer "In6.Cu")
		(net "DMI_CPU0_PCH_TX_DP<4>")
	)
	(segment
		(start 351.949258 -71.63435)
		(end 351.759012 -71.17461)
		(width 0.14732)
		(layer "In6.Cu")
		(net "DMI_CPU0_PCH_TX_DP<4>")
	)
	(segment
		(start 370.483384 -222.77578)
		(end 370.483384 -222.761556)
		(width 0.0889)
		(layer "In6.Cu")
		(net "DMI_CPU0_PCH_TX_DP<4>")
	)
	(segment
		(start 371.601746 -219.18676)
		(end 371.610636 -219.18168)
		(width 0.0889)
		(layer "In6.Cu")
		(net "DMI_CPU0_PCH_TX_DP<4>")
	)
	(segment
		(start 369.722146 -225.69805)
		(end 369.731036 -225.69297)
		(width 0.0889)
		(layer "In6.Cu")
		(net "DMI_CPU0_PCH_TX_DP<4>")
	)
	(segment
		(start 369.731036 -224.7138)
		(end 369.722146 -224.70872)
		(width 0.0889)
		(layer "In6.Cu")
		(net "DMI_CPU0_PCH_TX_DP<4>")
	)
	(segment
		(start 372.071392 -218.372944)
		(end 372.086378 -218.364308)
		(width 0.0889)
		(layer "In6.Cu")
		(net "DMI_CPU0_PCH_TX_DP<4>")
	)
	(segment
		(start 350.917256 -69.142102)
		(end 350.41713 -68.641976)
		(width 0.14732)
		(layer "In6.Cu")
		(net "DMI_CPU0_PCH_TX_DP<4>")
	)
	(segment
		(start 373.855234 -211.272628)
		(end 373.855234 -211.25053)
		(width 0.0889)
		(layer "In6.Cu")
		(net "DMI_CPU0_PCH_TX_DP<4>")
	)
	(segment
		(start 372.83263 -215.452198)
		(end 372.83263 -215.436704)
		(width 0.0889)
		(layer "In6.Cu")
		(net "DMI_CPU0_PCH_TX_DP<4>")
	)
	(segment
		(start 352.048318 -72.0598)
		(end 351.949258 -71.63435)
		(width 0.14732)
		(layer "In6.Cu")
		(net "DMI_CPU0_PCH_TX_DP<4>")
	)
	(segment
		(start 373.136414 -215.02243)
		(end 373.81307 -214.345774)
		(width 0.0889)
		(layer "In6.Cu")
		(net "DMI_CPU0_PCH_TX_DP<4>")
	)
	(segment
		(start 352.203258 -72.722994)
		(end 352.29419 -72.576436)
		(width 0.14732)
		(layer "In6.Cu")
		(net "DMI_CPU0_PCH_TX_DP<4>")
	)
	(segment
		(start 371.89283 -218.707716)
		(end 371.89283 -218.692222)
		(width 0.0889)
		(layer "In6.Cu")
		(net "DMI_CPU0_PCH_TX_DP<4>")
	)
	(segment
		(start 351.825052 -71.015352)
		(end 351.65792 -70.611238)
		(width 0.14732)
		(layer "In6.Cu")
		(net "DMI_CPU0_PCH_TX_DP<4>")
	)
	(segment
		(start 365.48695 -229.77094)
		(end 365.501682 -229.762304)
		(width 0.0889)
		(layer "In6.Cu")
		(net "DMI_CPU0_PCH_TX_DP<4>")
	)
	(segment
		(start 350.41713 -68.641976)
		(end 350.41713 -68.46951)
		(width 0.14732)
		(layer "In6.Cu")
		(net "DMI_CPU0_PCH_TX_DP<4>")
	)
	(segment
		(start 371.423184 -219.515944)
		(end 371.423184 -219.506038)
		(width 0.0889)
		(layer "In6.Cu")
		(net "DMI_CPU0_PCH_TX_DP<4>")
	)
	(segment
		(start 373.81307 -211.314792)
		(end 373.855234 -211.272628)
		(width 0.0889)
		(layer "In6.Cu")
		(net "DMI_CPU0_PCH_TX_DP<4>")
	)
	(segment
		(start 371.131592 -221.628462)
		(end 371.146578 -221.619826)
		(width 0.0889)
		(layer "In6.Cu")
		(net "DMI_CPU0_PCH_TX_DP<4>")
	)
	(segment
		(start 370.013484 -223.585532)
		(end 370.013484 -223.56699)
		(width 0.0889)
		(layer "In6.Cu")
		(net "DMI_CPU0_PCH_TX_DP<4>")
	)
	(segment
		(start 373.855234 -211.25053)
		(end 373.855234 -210.881722)
		(width 0.14732)
		(layer "In6.Cu")
		(net "DMI_CPU0_PCH_TX_DP<4>")
	)
	(segment
		(start 351.230184 -69.578474)
		(end 351.070672 -69.512434)
		(width 0.14732)
		(layer "In6.Cu")
		(net "DMI_CPU0_PCH_TX_DP<4>")
	)
	(segment
		(start 391.874248 -178.976274)
		(end 385.831334 -144.70634)
		(width 0.14732)
		(layer "In6.Cu")
		(net "DMI_CPU0_PCH_TX_DP<4>")
	)
	(segment
		(start 373.85498 -209.770218)
		(end 374.019318 -208.834482)
		(width 0.14732)
		(layer "In6.Cu")
		(net "DMI_CPU0_PCH_TX_DP<4>")
	)
	(segment
		(start 368.793522 -227.319332)
		(end 368.797332 -227.317046)
		(width 0.0889)
		(layer "In6.Cu")
		(net "DMI_CPU0_PCH_TX_DP<4>")
	)
	(segment
		(start 353.869498 -79.870554)
		(end 352.203258 -72.722994)
		(width 0.14732)
		(layer "In6.Cu")
		(net "DMI_CPU0_PCH_TX_DP<4>")
	)
	(segment
		(start 372.541546 -215.931242)
		(end 372.550436 -215.926162)
		(width 0.0889)
		(layer "In6.Cu")
		(net "DMI_CPU0_PCH_TX_DP<4>")
	)
	(segment
		(start 351.331276 -70.141846)
		(end 351.397316 -69.982334)
		(width 0.14732)
		(layer "In6.Cu")
		(net "DMI_CPU0_PCH_TX_DP<4>")
	)
	(segment
		(start 364.654084 -229.272846)
		(end 364.654084 -229.28834)
		(width 0.0889)
		(layer "In6.Cu")
		(net "DMI_CPU0_PCH_TX_DP<4>")
	)
	(segment
		(start 368.782346 -227.325682)
		(end 368.793522 -227.319332)
		(width 0.0889)
		(layer "In6.Cu")
		(net "DMI_CPU0_PCH_TX_DP<4>")
	)
	(segment
		(start 369.252246 -226.511866)
		(end 369.260374 -226.507294)
		(width 0.0889)
		(layer "In6.Cu")
		(net "DMI_CPU0_PCH_TX_DP<4>")
	)
	(segment
		(start 373.813324 -212.716364)
		(end 373.813324 -211.571078)
		(width 0.0889)
		(layer "In6.Cu")
		(net "DMI_CPU0_PCH_TX_DP<4>")
	)
	(segment
		(start 367.286032 -228.948488)
		(end 367.300764 -228.957124)
		(width 0.0889)
		(layer "In6.Cu")
		(net "DMI_CPU0_PCH_TX_DP<4>")
	)
	(segment
		(start 363.652816 -228.188012)
		(end 363.673898 -228.110034)
		(width 0.0889)
		(layer "In6.Cu")
		(net "DMI_CPU0_PCH_TX_DP<4>")
	)
	(segment
		(start 389.68172 -191.408812)
		(end 391.874248 -178.976274)
		(width 0.14732)
		(layer "In6.Cu")
		(net "DMI_CPU0_PCH_TX_DP<4>")
	)
	(segment
		(start 370.01323 -225.225356)
		(end 370.01323 -225.187764)
		(width 0.0889)
		(layer "In6.Cu")
		(net "DMI_CPU0_PCH_TX_DP<4>")
	)
	(segment
		(start 371.139974 -219.996004)
		(end 371.140736 -219.995496)
		(width 0.0889)
		(layer "In6.Cu")
		(net "DMI_CPU0_PCH_TX_DP<4>")
	)
	(segment
		(start 368.13363 -228.474524)
		(end 368.13363 -228.45903)
		(width 0.0889)
		(layer "In6.Cu")
		(net "DMI_CPU0_PCH_TX_DP<4>")
	)
	(segment
		(start 364.460536 -228.944932)
		(end 364.463838 -228.946964)
		(width 0.0889)
		(layer "In6.Cu")
		(net "DMI_CPU0_PCH_TX_DP<4>")
	)
	(segment
		(start 385.831334 -144.70634)
		(end 353.869498 -79.870554)
		(width 0.14732)
		(layer "In6.Cu")
		(net "DMI_CPU0_PCH_TX_DP<4>")
	)
	(segment
		(start 368.603784 -227.659184)
		(end 368.603784 -227.64496)
		(width 0.0889)
		(layer "In6.Cu")
		(net "DMI_CPU0_PCH_TX_DP<4>")
	)
	(segment
		(start 384.757168 -198.441564)
		(end 389.68172 -191.408812)
		(width 0.14732)
		(layer "In6.Cu")
		(net "DMI_CPU0_PCH_TX_DP<4>")
	)
	(segment
		(start 351.65792 -70.611238)
		(end 351.498408 -70.545452)
		(width 0.14732)
		(layer "In6.Cu")
		(net "DMI_CPU0_PCH_TX_DP<4>")
	)
	(segment
		(start 371.131846 -220.000576)
		(end 371.139974 -219.996004)
		(width 0.0889)
		(layer "In6.Cu")
		(net "DMI_CPU0_PCH_TX_DP<4>")
	)
	(segment
		(start 351.397316 -69.982334)
		(end 351.230184 -69.578474)
		(width 0.14732)
		(layer "In6.Cu")
		(net "DMI_CPU0_PCH_TX_DP<4>")
	)
	(segment
		(start 349.425768 -66.836544)
		(end 349.593408 -66.668904)
		(width 0.14732)
		(layer "In6.Cu")
		(net "DMI_CPU0_PCH_TX_DP<4>")
	)
	(segment
		(start 371.140736 -220.644212)
		(end 371.131846 -220.639132)
		(width 0.0889)
		(layer "In6.Cu")
		(net "DMI_CPU0_PCH_TX_DP<4>")
	)
	(segment
		(start 352.29419 -72.576436)
		(end 352.194876 -72.150732)
		(width 0.14732)
		(layer "In6.Cu")
		(net "DMI_CPU0_PCH_TX_DP<4>")
	)
	(segment
		(start 364.466632 -228.948488)
		(end 364.468156 -228.94925)
		(width 0.0889)
		(layer "In6.Cu")
		(net "DMI_CPU0_PCH_TX_DP<4>")
	)
	(segment
		(start 364.468156 -228.94925)
		(end 364.475522 -228.953568)
		(width 0.0889)
		(layer "In6.Cu")
		(net "DMI_CPU0_PCH_TX_DP<4>")
	)
	(segment
		(start 350.107758 -68.160138)
		(end 349.935292 -68.160138)
		(width 0.14732)
		(layer "In6.Cu")
		(net "DMI_CPU0_PCH_TX_DP<4>")
	)
	(segment
		(start 372.081044 -216.73947)
		(end 372.086378 -216.736422)
		(width 0.0889)
		(layer "In6.Cu")
		(net "DMI_CPU0_PCH_TX_DP<4>")
	)
	(segment
		(start 369.543584 -226.027234)
		(end 369.543584 -226.017328)
		(width 0.0889)
		(layer "In6.Cu")
		(net "DMI_CPU0_PCH_TX_DP<4>")
	)
	(segment
		(start 371.893084 -217.072972)
		(end 371.893084 -217.0557)
		(width 0.0889)
		(layer "In6.Cu")
		(net "DMI_CPU0_PCH_TX_DP<4>")
	)
	(segment
		(start 350.357948 -66.668904)
		(end 350.652588 -66.963544)
		(width 0.14732)
		(layer "In6.Cu")
		(net "DMI_CPU0_PCH_TX_DP<4>")
	)
	(segment
		(start 373.85498 -210.881468)
		(end 373.85498 -209.770218)
		(width 0.14732)
		(layer "In6.Cu")
		(net "DMI_CPU0_PCH_TX_DP<4>")
	)
	(segment
		(start 349.425768 -67.650614)
		(end 349.425768 -66.836544)
		(width 0.14732)
		(layer "In6.Cu")
		(net "DMI_CPU0_PCH_TX_DP<4>")
	)
	(segment
		(start 368.312192 -228.139752)
		(end 368.321082 -228.134672)
		(width 0.0889)
		(layer "In6.Cu")
		(net "DMI_CPU0_PCH_TX_DP<4>")
	)
	(segment
		(start 369.260374 -226.507294)
		(end 369.261136 -226.506786)
		(width 0.0889)
		(layer "In6.Cu")
		(net "DMI_CPU0_PCH_TX_DP<4>")
	)
	(segment
		(start 372.080282 -216.739978)
		(end 372.081044 -216.73947)
		(width 0.0889)
		(layer "In6.Cu")
		(net "DMI_CPU0_PCH_TX_DP<4>")
	)
	(segment
		(start 349.935292 -68.160138)
		(end 349.425768 -67.650614)
		(width 0.14732)
		(layer "In6.Cu")
		(net "DMI_CPU0_PCH_TX_DP<4>")
	)
	(segment
		(start 370.95303 -221.963234)
		(end 370.95303 -221.94774)
		(width 0.0889)
		(layer "In6.Cu")
		(net "DMI_CPU0_PCH_TX_DP<4>")
	)
	(segment
		(start 373.81307 -214.345774)
		(end 373.81307 -212.716618)
		(width 0.0889)
		(layer "In6.Cu")
		(net "DMI_CPU0_PCH_TX_DP<4>")
	)
	(segment
		(start 373.011192 -215.117426)
		(end 373.01932 -215.112092)
		(width 0.0889)
		(layer "In6.Cu")
		(net "DMI_CPU0_PCH_TX_DP<4>")
	)
	(segment
		(start 351.759012 -71.17461)
		(end 351.825052 -71.015352)
		(width 0.14732)
		(layer "In6.Cu")
		(net "DMI_CPU0_PCH_TX_DP<4>")
	)
	(segment
		(start 377.966732 -203.196444)
		(end 384.757168 -198.441564)
		(width 0.14732)
		(layer "In6.Cu")
		(net "DMI_CPU0_PCH_TX_DP<4>")
	)
	(segment
		(start 373.81307 -211.570824)
		(end 373.81307 -211.314792)
		(width 0.0889)
		(layer "In6.Cu")
		(net "DMI_CPU0_PCH_TX_DP<4>")
	)
	(segment
		(start 373.81307 -212.716618)
		(end 373.813324 -212.716364)
		(width 0.0889)
		(layer "In6.Cu")
		(net "DMI_CPU0_PCH_TX_DP<4>")
	)
	(segment
		(start 373.813324 -211.571078)
		(end 373.81307 -211.570824)
		(width 0.0889)
		(layer "In6.Cu")
		(net "DMI_CPU0_PCH_TX_DP<4>")
	)
	(segment
		(start 373.855234 -210.881722)
		(end 373.85498 -210.881468)
		(width 0.14732)
		(layer "In6.Cu")
		(net "DMI_CPU0_PCH_TX_DP<4>")
	)
	(segment
		(start 370.661946 -222.442278)
		(end 370.670836 -222.437198)
		(width 0.0889)
		(layer "In6.Cu")
		(net "DMI_CPU0_PCH_TX_DP<4>")
	)
	(segment
		(start 351.498408 -70.545452)
		(end 351.331276 -70.141846)
		(width 0.14732)
		(layer "In6.Cu")
		(net "DMI_CPU0_PCH_TX_DP<4>")
	)
	(segment
		(start 369.722146 -224.070164)
		(end 369.731036 -224.065084)
		(width 0.0889)
		(layer "In6.Cu")
		(net "DMI_CPU0_PCH_TX_DP<4>")
	)
	(segment
		(start 374.019318 -208.834482)
		(end 377.966732 -203.196444)
		(width 0.14732)
		(layer "In6.Cu")
		(net "DMI_CPU0_PCH_TX_DP<4>")
	)
	(segment
		(start 351.070672 -69.512434)
		(end 350.917256 -69.142102)
		(width 0.14732)
		(layer "In6.Cu")
		(net "DMI_CPU0_PCH_TX_DP<4>")
	)
	(segment
		(start 349.593408 -66.668904)
		(end 350.357948 -66.668904)
		(width 0.14732)
		(layer "In6.Cu")
		(net "DMI_CPU0_PCH_TX_DP<4>")
	)
	(arc
		(start 368.797332 -227.317046)
		(mid 368.999745 -227.110633)
		(end 369.073684 -226.831144)
		(width 0.0889)
		(layer "In6.Cu")
		(net "DMI_CPU0_PCH_TX_DP<4>")
	)
	(arc
		(start 369.543838 -226.002596)
		(mid 369.594892 -225.828016)
		(end 369.722146 -225.69805)
		(width 0.0889)
		(layer "In6.Cu")
		(net "DMI_CPU0_PCH_TX_DP<4>")
	)
	(arc
		(start 364.183676 -228.444298)
		(mid 364.183873 -228.451663)
		(end 364.18393 -228.45903)
		(width 0.0889)
		(layer "In6.Cu")
		(net "DMI_CPU0_PCH_TX_DP<4>")
	)
	(arc
		(start 363.673898 -228.110034)
		(mid 364.014709 -228.14607)
		(end 364.183676 -228.444298)
		(width 0.0889)
		(layer "In6.Cu")
		(net "DMI_CPU0_PCH_TX_DP<4>")
	)
	(arc
		(start 371.423184 -219.506038)
		(mid 371.470863 -219.323138)
		(end 371.601746 -219.18676)
		(width 0.0889)
		(layer "In6.Cu")
		(net "DMI_CPU0_PCH_TX_DP<4>")
	)
	(arc
		(start 371.131846 -220.639132)
		(mid 370.953249 -220.319854)
		(end 371.131846 -220.000576)
		(width 0.0889)
		(layer "In6.Cu")
		(net "DMI_CPU0_PCH_TX_DP<4>")
	)
	(arc
		(start 369.731036 -224.065084)
		(mid 369.935371 -223.862479)
		(end 370.013484 -223.585532)
		(width 0.0889)
		(layer "In6.Cu")
		(net "DMI_CPU0_PCH_TX_DP<4>")
	)
	(arc
		(start 369.731036 -225.69297)
		(mid 369.932318 -225.495483)
		(end 370.01323 -225.225356)
		(width 0.0889)
		(layer "In6.Cu")
		(net "DMI_CPU0_PCH_TX_DP<4>")
	)
	(arc
		(start 369.722146 -224.70872)
		(mid 369.543549 -224.389442)
		(end 369.722146 -224.070164)
		(width 0.0889)
		(layer "In6.Cu")
		(net "DMI_CPU0_PCH_TX_DP<4>")
	)
	(arc
		(start 370.670836 -222.437198)
		(mid 370.873659 -222.236967)
		(end 370.95303 -221.963234)
		(width 0.0889)
		(layer "In6.Cu")
		(net "DMI_CPU0_PCH_TX_DP<4>")
	)
	(arc
		(start 370.483384 -222.761556)
		(mid 370.531063 -222.578656)
		(end 370.661946 -222.442278)
		(width 0.0889)
		(layer "In6.Cu")
		(net "DMI_CPU0_PCH_TX_DP<4>")
	)
	(arc
		(start 367.300764 -228.957124)
		(mid 367.851957 -228.948326)
		(end 368.13363 -228.474524)
		(width 0.0889)
		(layer "In6.Cu")
		(net "DMI_CPU0_PCH_TX_DP<4>")
	)
	(arc
		(start 368.321082 -228.134672)
		(mid 368.524563 -227.933868)
		(end 368.603784 -227.659184)
		(width 0.0889)
		(layer "In6.Cu")
		(net "DMI_CPU0_PCH_TX_DP<4>")
	)
	(arc
		(start 368.603784 -227.64496)
		(mid 368.651463 -227.46206)
		(end 368.782346 -227.325682)
		(width 0.0889)
		(layer "In6.Cu")
		(net "DMI_CPU0_PCH_TX_DP<4>")
	)
	(arc
		(start 370.01323 -225.187764)
		(mid 369.93386 -224.91403)
		(end 369.731036 -224.7138)
		(width 0.0889)
		(layer "In6.Cu")
		(net "DMI_CPU0_PCH_TX_DP<4>")
	)
	(arc
		(start 369.543584 -226.017328)
		(mid 369.543636 -226.009961)
		(end 369.543838 -226.002596)
		(width 0.0889)
		(layer "In6.Cu")
		(net "DMI_CPU0_PCH_TX_DP<4>")
	)
	(arc
		(start 365.876078 -229.762304)
		(mid 366.441355 -229.762378)
		(end 366.724184 -229.272846)
		(width 0.0889)
		(layer "In6.Cu")
		(net "DMI_CPU0_PCH_TX_DP<4>")
	)
	(arc
		(start 364.475522 -228.953568)
		(mid 364.606436 -229.089928)
		(end 364.654084 -229.272846)
		(width 0.0889)
		(layer "In6.Cu")
		(net "DMI_CPU0_PCH_TX_DP<4>")
	)
	(arc
		(start 371.610636 -219.18168)
		(mid 371.813459 -218.981449)
		(end 371.89283 -218.707716)
		(width 0.0889)
		(layer "In6.Cu")
		(net "DMI_CPU0_PCH_TX_DP<4>")
	)
	(arc
		(start 366.724184 -229.272846)
		(mid 366.911483 -228.948405)
		(end 367.286032 -228.948488)
		(width 0.0889)
		(layer "In6.Cu")
		(net "DMI_CPU0_PCH_TX_DP<4>")
	)
	(arc
		(start 371.893084 -217.0557)
		(mid 371.945354 -216.873335)
		(end 372.080282 -216.739978)
		(width 0.0889)
		(layer "In6.Cu")
		(net "DMI_CPU0_PCH_TX_DP<4>")
	)
	(arc
		(start 364.18393 -228.45903)
		(mid 364.257921 -228.738596)
		(end 364.460536 -228.944932)
		(width 0.0889)
		(layer "In6.Cu")
		(net "DMI_CPU0_PCH_TX_DP<4>")
	)
	(arc
		(start 370.95303 -221.94774)
		(mid 371.000709 -221.76484)
		(end 371.131592 -221.628462)
		(width 0.0889)
		(layer "In6.Cu")
		(net "DMI_CPU0_PCH_TX_DP<4>")
	)
	(arc
		(start 370.013484 -223.56699)
		(mid 370.065754 -223.384625)
		(end 370.200682 -223.251268)
		(width 0.0889)
		(layer "In6.Cu")
		(net "DMI_CPU0_PCH_TX_DP<4>")
	)
	(arc
		(start 372.550436 -215.926162)
		(mid 372.753259 -215.725931)
		(end 372.83263 -215.452198)
		(width 0.0889)
		(layer "In6.Cu")
		(net "DMI_CPU0_PCH_TX_DP<4>")
	)
	(arc
		(start 369.073684 -226.831144)
		(mid 369.121363 -226.648244)
		(end 369.252246 -226.511866)
		(width 0.0889)
		(layer "In6.Cu")
		(net "DMI_CPU0_PCH_TX_DP<4>")
	)
	(arc
		(start 369.261136 -226.506786)
		(mid 369.465471 -226.304181)
		(end 369.543584 -226.027234)
		(width 0.0889)
		(layer "In6.Cu")
		(net "DMI_CPU0_PCH_TX_DP<4>")
	)
	(arc
		(start 371.140736 -219.995496)
		(mid 371.345071 -219.792891)
		(end 371.423184 -219.515944)
		(width 0.0889)
		(layer "In6.Cu")
		(net "DMI_CPU0_PCH_TX_DP<4>")
	)
	(arc
		(start 372.362984 -216.25052)
		(mid 372.410663 -216.06762)
		(end 372.541546 -215.931242)
		(width 0.0889)
		(layer "In6.Cu")
		(net "DMI_CPU0_PCH_TX_DP<4>")
	)
	(arc
		(start 371.146578 -221.619826)
		(mid 371.42336 -221.130315)
		(end 371.140736 -220.644212)
		(width 0.0889)
		(layer "In6.Cu")
		(net "DMI_CPU0_PCH_TX_DP<4>")
	)
	(arc
		(start 364.654084 -229.28834)
		(mid 364.935816 -229.762038)
		(end 365.48695 -229.77094)
		(width 0.0889)
		(layer "In6.Cu")
		(net "DMI_CPU0_PCH_TX_DP<4>")
	)
	(arc
		(start 372.086378 -218.364308)
		(mid 372.362941 -217.874814)
		(end 372.080282 -217.388694)
		(width 0.0889)
		(layer "In6.Cu")
		(net "DMI_CPU0_PCH_TX_DP<4>")
	)
	(arc
		(start 371.89283 -218.692222)
		(mid 371.940509 -218.509322)
		(end 372.071392 -218.372944)
		(width 0.0889)
		(layer "In6.Cu")
		(net "DMI_CPU0_PCH_TX_DP<4>")
	)
	(arc
		(start 373.01932 -215.112092)
		(mid 373.080804 -215.071097)
		(end 373.136414 -215.02243)
		(width 0.0889)
		(layer "In6.Cu")
		(net "DMI_CPU0_PCH_TX_DP<4>")
	)
	(arc
		(start 370.200682 -223.251268)
		(mid 370.404163 -223.050464)
		(end 370.483384 -222.77578)
		(width 0.0889)
		(layer "In6.Cu")
		(net "DMI_CPU0_PCH_TX_DP<4>")
	)
	(arc
		(start 368.13363 -228.45903)
		(mid 368.181309 -228.27613)
		(end 368.312192 -228.139752)
		(width 0.0889)
		(layer "In6.Cu")
		(net "DMI_CPU0_PCH_TX_DP<4>")
	)
	(arc
		(start 372.83263 -215.436704)
		(mid 372.880309 -215.253804)
		(end 373.011192 -215.117426)
		(width 0.0889)
		(layer "In6.Cu")
		(net "DMI_CPU0_PCH_TX_DP<4>")
	)
	(arc
		(start 372.080282 -217.388694)
		(mid 371.945349 -217.25534)
		(end 371.893084 -217.072972)
		(width 0.0889)
		(layer "In6.Cu")
		(net "DMI_CPU0_PCH_TX_DP<4>")
	)
	(arc
		(start 365.501682 -229.762304)
		(mid 365.68888 -229.712161)
		(end 365.876078 -229.762304)
		(width 0.0889)
		(layer "In6.Cu")
		(net "DMI_CPU0_PCH_TX_DP<4>")
	)
	(arc
		(start 372.086378 -216.736422)
		(mid 372.288965 -216.530071)
		(end 372.362984 -216.25052)
		(width 0.0889)
		(layer "In6.Cu")
		(net "DMI_CPU0_PCH_TX_DP<4>")
	)
	(segment
		(start 362.869734 -227.367084)
		(end 362.869734 -226.831144)
		(width 0.13208)
		(layer "F.Cu")
		(net "DMI_CPU0_PCH_TX_DP<3>")
	)
	(segment
		(start 349.608394 -68.80352)
		(end 351.811082 -68.80352)
		(width 0.13208)
		(layer "F.Cu")
		(net "DMI_CPU0_PCH_TX_DP<3>")
	)
	(segment
		(start 349.280734 -69.13118)
		(end 349.608394 -68.80352)
		(width 0.13208)
		(layer "F.Cu")
		(net "DMI_CPU0_PCH_TX_DP<3>")
	)
	(segment
		(start 351.811082 -68.80352)
		(end 352.113342 -69.10578)
		(width 0.13208)
		(layer "F.Cu")
		(net "DMI_CPU0_PCH_TX_DP<3>")
	)
	(segment
		(start 371.982238 -221.459806)
		(end 371.985032 -221.458282)
		(width 0.0889)
		(layer "In6.Cu")
		(net "DMI_CPU0_PCH_TX_DP<3>")
	)
	(segment
		(start 373.942356 -214.887556)
		(end 374.518174 -214.311738)
		(width 0.0889)
		(layer "In6.Cu")
		(net "DMI_CPU0_PCH_TX_DP<3>")
	)
	(segment
		(start 353.656138 -75.606656)
		(end 353.50958 -75.51547)
		(width 0.14732)
		(layer "In6.Cu")
		(net "DMI_CPU0_PCH_TX_DP<3>")
	)
	(segment
		(start 390.269476 -191.652144)
		(end 392.50493 -178.976274)
		(width 0.14732)
		(layer "In6.Cu")
		(net "DMI_CPU0_PCH_TX_DP<3>")
	)
	(segment
		(start 362.965238 -227.64496)
		(end 362.965238 -227.653596)
		(width 0.0889)
		(layer "In6.Cu")
		(net "DMI_CPU0_PCH_TX_DP<3>")
	)
	(segment
		(start 371.985032 -221.458282)
		(end 371.986556 -221.45752)
		(width 0.0889)
		(layer "In6.Cu")
		(net "DMI_CPU0_PCH_TX_DP<3>")
	)
	(segment
		(start 371.232684 -222.761556)
		(end 371.232684 -222.746062)
		(width 0.0889)
		(layer "In6.Cu")
		(net "DMI_CPU0_PCH_TX_DP<3>")
	)
	(segment
		(start 362.71327 -227.102162)
		(end 362.7374 -227.191316)
		(width 0.0889)
		(layer "In6.Cu")
		(net "DMI_CPU0_PCH_TX_DP<3>")
	)
	(segment
		(start 371.514878 -222.272098)
		(end 371.523768 -222.267018)
		(width 0.0889)
		(layer "In6.Cu")
		(net "DMI_CPU0_PCH_TX_DP<3>")
	)
	(segment
		(start 371.986556 -221.45752)
		(end 371.993922 -221.453202)
		(width 0.0889)
		(layer "In6.Cu")
		(net "DMI_CPU0_PCH_TX_DP<3>")
	)
	(segment
		(start 374.419114 -212.231478)
		(end 374.518174 -212.132418)
		(width 0.0889)
		(layer "In6.Cu")
		(net "DMI_CPU0_PCH_TX_DP<3>")
	)
	(segment
		(start 372.93169 -218.198954)
		(end 372.933722 -218.197684)
		(width 0.0889)
		(layer "In6.Cu")
		(net "DMI_CPU0_PCH_TX_DP<3>")
	)
	(segment
		(start 385.203192 -198.887588)
		(end 390.269476 -191.652144)
		(width 0.14732)
		(layer "In6.Cu")
		(net "DMI_CPU0_PCH_TX_DP<3>")
	)
	(segment
		(start 363.43463 -228.436932)
		(end 363.43463 -228.45903)
		(width 0.0889)
		(layer "In6.Cu")
		(net "DMI_CPU0_PCH_TX_DP<3>")
	)
	(segment
		(start 372.933722 -217.559128)
		(end 372.925594 -217.554556)
		(width 0.0889)
		(layer "In6.Cu")
		(net "DMI_CPU0_PCH_TX_DP<3>")
	)
	(segment
		(start 368.695478 -228.783388)
		(end 368.696494 -228.78288)
		(width 0.0889)
		(layer "In6.Cu")
		(net "DMI_CPU0_PCH_TX_DP<3>")
	)
	(segment
		(start 352.906076 -72.911716)
		(end 352.997262 -72.765412)
		(width 0.14732)
		(layer "In6.Cu")
		(net "DMI_CPU0_PCH_TX_DP<3>")
	)
	(segment
		(start 370.292884 -224.404936)
		(end 370.292884 -224.373948)
		(width 0.0889)
		(layer "In6.Cu")
		(net "DMI_CPU0_PCH_TX_DP<3>")
	)
	(segment
		(start 364.560358 -230.410258)
		(end 364.561882 -230.41102)
		(width 0.0889)
		(layer "In6.Cu")
		(net "DMI_CPU0_PCH_TX_DP<3>")
	)
	(segment
		(start 353.908614 -76.695554)
		(end 353.762056 -76.604368)
		(width 0.14732)
		(layer "In6.Cu")
		(net "DMI_CPU0_PCH_TX_DP<3>")
	)
	(segment
		(start 374.47601 -211.780628)
		(end 374.47601 -211.75853)
		(width 0.0889)
		(layer "In6.Cu")
		(net "DMI_CPU0_PCH_TX_DP<3>")
	)
	(segment
		(start 364.552992 -230.40594)
		(end 364.560358 -230.410258)
		(width 0.0889)
		(layer "In6.Cu")
		(net "DMI_CPU0_PCH_TX_DP<3>")
	)
	(segment
		(start 352.763836 -68.95846)
		(end 352.616516 -68.81114)
		(width 0.14732)
		(layer "In6.Cu")
		(net "DMI_CPU0_PCH_TX_DP<3>")
	)
	(segment
		(start 354.592128 -79.643224)
		(end 353.908614 -76.695554)
		(width 0.14732)
		(layer "In6.Cu")
		(net "DMI_CPU0_PCH_TX_DP<3>")
	)
	(segment
		(start 372.925594 -217.554556)
		(end 372.924832 -217.554048)
		(width 0.0889)
		(layer "In6.Cu")
		(net "DMI_CPU0_PCH_TX_DP<3>")
	)
	(segment
		(start 368.88293 -228.45903)
		(end 368.88293 -228.444806)
		(width 0.0889)
		(layer "In6.Cu")
		(net "DMI_CPU0_PCH_TX_DP<3>")
	)
	(segment
		(start 352.616516 -68.81114)
		(end 352.407982 -68.81114)
		(width 0.14732)
		(layer "In6.Cu")
		(net "DMI_CPU0_PCH_TX_DP<3>")
	)
	(segment
		(start 373.858536 -214.950802)
		(end 373.864632 -214.947246)
		(width 0.0889)
		(layer "In6.Cu")
		(net "DMI_CPU0_PCH_TX_DP<3>")
	)
	(segment
		(start 352.407982 -68.81114)
		(end 352.113342 -69.10578)
		(width 0.14732)
		(layer "In6.Cu")
		(net "DMI_CPU0_PCH_TX_DP<3>")
	)
	(segment
		(start 374.419114 -213.222078)
		(end 374.419114 -212.957918)
		(width 0.0889)
		(layer "In6.Cu")
		(net "DMI_CPU0_PCH_TX_DP<3>")
	)
	(segment
		(start 371.978936 -219.833952)
		(end 371.993922 -219.825316)
		(width 0.0889)
		(layer "In6.Cu")
		(net "DMI_CPU0_PCH_TX_DP<3>")
	)
	(segment
		(start 370.099336 -226.345242)
		(end 370.114322 -226.336606)
		(width 0.0889)
		(layer "In6.Cu")
		(net "DMI_CPU0_PCH_TX_DP<3>")
	)
	(segment
		(start 378.412756 -203.642468)
		(end 385.203192 -198.887588)
		(width 0.14732)
		(layer "In6.Cu")
		(net "DMI_CPU0_PCH_TX_DP<3>")
	)
	(segment
		(start 371.70233 -220.334078)
		(end 371.70233 -220.319854)
		(width 0.0889)
		(layer "In6.Cu")
		(net "DMI_CPU0_PCH_TX_DP<3>")
	)
	(segment
		(start 372.172484 -219.506038)
		(end 372.172484 -219.490544)
		(width 0.0889)
		(layer "In6.Cu")
		(net "DMI_CPU0_PCH_TX_DP<3>")
	)
	(segment
		(start 386.45592 -144.66951)
		(end 354.592128 -79.643224)
		(width 0.14732)
		(layer "In6.Cu")
		(net "DMI_CPU0_PCH_TX_DP<3>")
	)
	(segment
		(start 363.613192 -228.778308)
		(end 363.624876 -228.785166)
		(width 0.0889)
		(layer "In6.Cu")
		(net "DMI_CPU0_PCH_TX_DP<3>")
	)
	(segment
		(start 353.004628 -73.337674)
		(end 352.906076 -72.911716)
		(width 0.14732)
		(layer "In6.Cu")
		(net "DMI_CPU0_PCH_TX_DP<3>")
	)
	(segment
		(start 369.629436 -227.159058)
		(end 369.635532 -227.155502)
		(width 0.0889)
		(layer "In6.Cu")
		(net "DMI_CPU0_PCH_TX_DP<3>")
	)
	(segment
		(start 368.225832 -229.597204)
		(end 368.227356 -229.596442)
		(width 0.0889)
		(layer "In6.Cu")
		(net "DMI_CPU0_PCH_TX_DP<3>")
	)
	(segment
		(start 374.419114 -212.495638)
		(end 374.419114 -212.231478)
		(width 0.0889)
		(layer "In6.Cu")
		(net "DMI_CPU0_PCH_TX_DP<3>")
	)
	(segment
		(start 353.75469 -76.032106)
		(end 353.656138 -75.606656)
		(width 0.14732)
		(layer "In6.Cu")
		(net "DMI_CPU0_PCH_TX_DP<3>")
	)
	(segment
		(start 374.419114 -213.684358)
		(end 374.518174 -213.585298)
		(width 0.0889)
		(layer "In6.Cu")
		(net "DMI_CPU0_PCH_TX_DP<3>")
	)
	(segment
		(start 374.47601 -209.824574)
		(end 374.607328 -209.078068)
		(width 0.14732)
		(layer "In6.Cu")
		(net "DMI_CPU0_PCH_TX_DP<3>")
	)
	(segment
		(start 353.403662 -74.517758)
		(end 353.257104 -74.426572)
		(width 0.14732)
		(layer "In6.Cu")
		(net "DMI_CPU0_PCH_TX_DP<3>")
	)
	(segment
		(start 353.762056 -76.604368)
		(end 353.663504 -76.17841)
		(width 0.14732)
		(layer "In6.Cu")
		(net "DMI_CPU0_PCH_TX_DP<3>")
	)
	(segment
		(start 353.151186 -73.42886)
		(end 353.004628 -73.337674)
		(width 0.14732)
		(layer "In6.Cu")
		(net "DMI_CPU0_PCH_TX_DP<3>")
	)
	(segment
		(start 368.227356 -229.596442)
		(end 368.234722 -229.592124)
		(width 0.0889)
		(layer "In6.Cu")
		(net "DMI_CPU0_PCH_TX_DP<3>")
	)
	(segment
		(start 374.518174 -213.585298)
		(end 374.518174 -213.321138)
		(width 0.0889)
		(layer "In6.Cu")
		(net "DMI_CPU0_PCH_TX_DP<3>")
	)
	(segment
		(start 353.257104 -74.426572)
		(end 353.158552 -74.000614)
		(width 0.14732)
		(layer "In6.Cu")
		(net "DMI_CPU0_PCH_TX_DP<3>")
	)
	(segment
		(start 374.518174 -211.822792)
		(end 374.47601 -211.780628)
		(width 0.0889)
		(layer "In6.Cu")
		(net "DMI_CPU0_PCH_TX_DP<3>")
	)
	(segment
		(start 373.58193 -215.44534)
		(end 373.58193 -215.436704)
		(width 0.0889)
		(layer "In6.Cu")
		(net "DMI_CPU0_PCH_TX_DP<3>")
	)
	(segment
		(start 370.76253 -223.575626)
		(end 370.76253 -223.568006)
		(width 0.0889)
		(layer "In6.Cu")
		(net "DMI_CPU0_PCH_TX_DP<3>")
	)
	(segment
		(start 352.641916 -71.184008)
		(end 352.641916 -70.747128)
		(width 0.14732)
		(layer "In6.Cu")
		(net "DMI_CPU0_PCH_TX_DP<3>")
	)
	(segment
		(start 374.518174 -212.858858)
		(end 374.518174 -212.594698)
		(width 0.0889)
		(layer "In6.Cu")
		(net "DMI_CPU0_PCH_TX_DP<3>")
	)
	(segment
		(start 368.413284 -229.272846)
		(end 368.413284 -229.257352)
		(width 0.0889)
		(layer "In6.Cu")
		(net "DMI_CPU0_PCH_TX_DP<3>")
	)
	(segment
		(start 374.419114 -212.957918)
		(end 374.518174 -212.858858)
		(width 0.0889)
		(layer "In6.Cu")
		(net "DMI_CPU0_PCH_TX_DP<3>")
	)
	(segment
		(start 353.411028 -75.089512)
		(end 353.502214 -74.943208)
		(width 0.14732)
		(layer "In6.Cu")
		(net "DMI_CPU0_PCH_TX_DP<3>")
	)
	(segment
		(start 372.454678 -219.01658)
		(end 372.463568 -219.0115)
		(width 0.0889)
		(layer "In6.Cu")
		(net "DMI_CPU0_PCH_TX_DP<3>")
	)
	(segment
		(start 364.083346 -229.592124)
		(end 364.092236 -229.597204)
		(width 0.0889)
		(layer "In6.Cu")
		(net "DMI_CPU0_PCH_TX_DP<3>")
	)
	(segment
		(start 365.48695 -230.402384)
		(end 365.501682 -230.41102)
		(width 0.0889)
		(layer "In6.Cu")
		(net "DMI_CPU0_PCH_TX_DP<3>")
	)
	(segment
		(start 374.518174 -213.321138)
		(end 374.419114 -213.222078)
		(width 0.0889)
		(layer "In6.Cu")
		(net "DMI_CPU0_PCH_TX_DP<3>")
	)
	(segment
		(start 372.91264 -216.58199)
		(end 372.933722 -216.569798)
		(width 0.0889)
		(layer "In6.Cu")
		(net "DMI_CPU0_PCH_TX_DP<3>")
	)
	(segment
		(start 370.292884 -226.017328)
		(end 370.292884 -225.99523)
		(width 0.0889)
		(layer "In6.Cu")
		(net "DMI_CPU0_PCH_TX_DP<3>")
	)
	(segment
		(start 353.502214 -74.943208)
		(end 353.403662 -74.517758)
		(width 0.14732)
		(layer "In6.Cu")
		(net "DMI_CPU0_PCH_TX_DP<3>")
	)
	(segment
		(start 370.576094 -223.899476)
		(end 370.583968 -223.894904)
		(width 0.0889)
		(layer "In6.Cu")
		(net "DMI_CPU0_PCH_TX_DP<3>")
	)
	(segment
		(start 372.918736 -218.20632)
		(end 372.93169 -218.198954)
		(width 0.0889)
		(layer "In6.Cu")
		(net "DMI_CPU0_PCH_TX_DP<3>")
	)
	(segment
		(start 363.624876 -228.785166)
		(end 363.628178 -228.786944)
		(width 0.0889)
		(layer "In6.Cu")
		(net "DMI_CPU0_PCH_TX_DP<3>")
	)
	(segment
		(start 371.045232 -223.085914)
		(end 371.054122 -223.080834)
		(width 0.0889)
		(layer "In6.Cu")
		(net "DMI_CPU0_PCH_TX_DP<3>")
	)
	(segment
		(start 370.575078 -223.899984)
		(end 370.576094 -223.899476)
		(width 0.0889)
		(layer "In6.Cu")
		(net "DMI_CPU0_PCH_TX_DP<3>")
	)
	(segment
		(start 352.997262 -72.765412)
		(end 352.763836 -71.758302)
		(width 0.14732)
		(layer "In6.Cu")
		(net "DMI_CPU0_PCH_TX_DP<3>")
	)
	(segment
		(start 353.158552 -74.000614)
		(end 353.249738 -73.85431)
		(width 0.14732)
		(layer "In6.Cu")
		(net "DMI_CPU0_PCH_TX_DP<3>")
	)
	(segment
		(start 352.763836 -70.625208)
		(end 352.763836 -68.95846)
		(width 0.14732)
		(layer "In6.Cu")
		(net "DMI_CPU0_PCH_TX_DP<3>")
	)
	(segment
		(start 374.518174 -212.594698)
		(end 374.419114 -212.495638)
		(width 0.0889)
		(layer "In6.Cu")
		(net "DMI_CPU0_PCH_TX_DP<3>")
	)
	(segment
		(start 353.50958 -75.51547)
		(end 353.411028 -75.089512)
		(width 0.14732)
		(layer "In6.Cu")
		(net "DMI_CPU0_PCH_TX_DP<3>")
	)
	(segment
		(start 368.696494 -228.78288)
		(end 368.704368 -228.778308)
		(width 0.0889)
		(layer "In6.Cu")
		(net "DMI_CPU0_PCH_TX_DP<3>")
	)
	(segment
		(start 392.50493 -178.976274)
		(end 386.45592 -144.66951)
		(width 0.14732)
		(layer "In6.Cu")
		(net "DMI_CPU0_PCH_TX_DP<3>")
	)
	(segment
		(start 352.641916 -70.747128)
		(end 352.763836 -70.625208)
		(width 0.14732)
		(layer "In6.Cu")
		(net "DMI_CPU0_PCH_TX_DP<3>")
	)
	(segment
		(start 374.419114 -213.948518)
		(end 374.419114 -213.684358)
		(width 0.0889)
		(layer "In6.Cu")
		(net "DMI_CPU0_PCH_TX_DP<3>")
	)
	(segment
		(start 373.112284 -216.25052)
		(end 373.112284 -216.240614)
		(width 0.0889)
		(layer "In6.Cu")
		(net "DMI_CPU0_PCH_TX_DP<3>")
	)
	(segment
		(start 370.583968 -224.88398)
		(end 370.576094 -224.879408)
		(width 0.0889)
		(layer "In6.Cu")
		(net "DMI_CPU0_PCH_TX_DP<3>")
	)
	(segment
		(start 369.82273 -226.83978)
		(end 369.82273 -226.831144)
		(width 0.0889)
		(layer "In6.Cu")
		(net "DMI_CPU0_PCH_TX_DP<3>")
	)
	(segment
		(start 371.978936 -221.461838)
		(end 371.982238 -221.459806)
		(width 0.0889)
		(layer "In6.Cu")
		(net "DMI_CPU0_PCH_TX_DP<3>")
	)
	(segment
		(start 374.518174 -212.132418)
		(end 374.518174 -211.822792)
		(width 0.0889)
		(layer "In6.Cu")
		(net "DMI_CPU0_PCH_TX_DP<3>")
	)
	(segment
		(start 370.575078 -225.527616)
		(end 370.583968 -225.522536)
		(width 0.0889)
		(layer "In6.Cu")
		(net "DMI_CPU0_PCH_TX_DP<3>")
	)
	(segment
		(start 374.518174 -214.311738)
		(end 374.518174 -214.047578)
		(width 0.0889)
		(layer "In6.Cu")
		(net "DMI_CPU0_PCH_TX_DP<3>")
	)
	(segment
		(start 352.763836 -71.758302)
		(end 352.763836 -71.305928)
		(width 0.14732)
		(layer "In6.Cu")
		(net "DMI_CPU0_PCH_TX_DP<3>")
	)
	(segment
		(start 352.763836 -71.305928)
		(end 352.641916 -71.184008)
		(width 0.14732)
		(layer "In6.Cu")
		(net "DMI_CPU0_PCH_TX_DP<3>")
	)
	(segment
		(start 366.42675 -230.402384)
		(end 366.441482 -230.41102)
		(width 0.0889)
		(layer "In6.Cu")
		(net "DMI_CPU0_PCH_TX_DP<3>")
	)
	(segment
		(start 369.35283 -227.653596)
		(end 369.35283 -227.64496)
		(width 0.0889)
		(layer "In6.Cu")
		(net "DMI_CPU0_PCH_TX_DP<3>")
	)
	(segment
		(start 353.249738 -73.85431)
		(end 353.151186 -73.42886)
		(width 0.14732)
		(layer "In6.Cu")
		(net "DMI_CPU0_PCH_TX_DP<3>")
	)
	(segment
		(start 374.607328 -209.078068)
		(end 378.412756 -203.642468)
		(width 0.14732)
		(layer "In6.Cu")
		(net "DMI_CPU0_PCH_TX_DP<3>")
	)
	(segment
		(start 371.993922 -220.814646)
		(end 371.985032 -220.809566)
		(width 0.0889)
		(layer "In6.Cu")
		(net "DMI_CPU0_PCH_TX_DP<3>")
	)
	(segment
		(start 353.663504 -76.17841)
		(end 353.75469 -76.032106)
		(width 0.14732)
		(layer "In6.Cu")
		(net "DMI_CPU0_PCH_TX_DP<3>")
	)
	(segment
		(start 374.47601 -211.75853)
		(end 374.47601 -209.824574)
		(width 0.14732)
		(layer "In6.Cu")
		(net "DMI_CPU0_PCH_TX_DP<3>")
	)
	(segment
		(start 362.869734 -226.831144)
		(end 362.71327 -227.102162)
		(width 0.0889)
		(layer "In6.Cu")
		(net "DMI_CPU0_PCH_TX_DP<3>")
	)
	(segment
		(start 364.37443 -230.071168)
		(end 364.37443 -230.086662)
		(width 0.0889)
		(layer "In6.Cu")
		(net "DMI_CPU0_PCH_TX_DP<3>")
	)
	(segment
		(start 370.576094 -224.879408)
		(end 370.575078 -224.8789)
		(width 0.0889)
		(layer "In6.Cu")
		(net "DMI_CPU0_PCH_TX_DP<3>")
	)
	(segment
		(start 374.518174 -214.047578)
		(end 374.419114 -213.948518)
		(width 0.0889)
		(layer "In6.Cu")
		(net "DMI_CPU0_PCH_TX_DP<3>")
	)
	(arc
		(start 368.88293 -228.444806)
		(mid 368.962149 -228.170121)
		(end 369.165632 -227.969318)
		(width 0.0889)
		(layer "In6.Cu")
		(net "DMI_CPU0_PCH_TX_DP<3>")
	)
	(arc
		(start 370.762276 -225.21799)
		(mid 370.762609 -225.205546)
		(end 370.76253 -225.193098)
		(width 0.0889)
		(layer "In6.Cu")
		(net "DMI_CPU0_PCH_TX_DP<3>")
	)
	(arc
		(start 369.35283 -227.64496)
		(mid 369.426821 -227.365394)
		(end 369.629436 -227.159058)
		(width 0.0889)
		(layer "In6.Cu")
		(net "DMI_CPU0_PCH_TX_DP<3>")
	)
	(arc
		(start 370.292884 -225.99523)
		(mid 370.373795 -225.725102)
		(end 370.575078 -225.527616)
		(width 0.0889)
		(layer "In6.Cu")
		(net "DMI_CPU0_PCH_TX_DP<3>")
	)
	(arc
		(start 370.76253 -225.193098)
		(mid 370.712461 -225.015873)
		(end 370.583968 -224.88398)
		(width 0.0889)
		(layer "In6.Cu")
		(net "DMI_CPU0_PCH_TX_DP<3>")
	)
	(arc
		(start 371.232684 -222.746062)
		(mid 371.312054 -222.472328)
		(end 371.514878 -222.272098)
		(width 0.0889)
		(layer "In6.Cu")
		(net "DMI_CPU0_PCH_TX_DP<3>")
	)
	(arc
		(start 371.985032 -220.809566)
		(mid 371.781551 -220.608762)
		(end 371.70233 -220.334078)
		(width 0.0889)
		(layer "In6.Cu")
		(net "DMI_CPU0_PCH_TX_DP<3>")
	)
	(arc
		(start 364.37443 -230.086662)
		(mid 364.422109 -230.269562)
		(end 364.552992 -230.40594)
		(width 0.0889)
		(layer "In6.Cu")
		(net "DMI_CPU0_PCH_TX_DP<3>")
	)
	(arc
		(start 367.00333 -230.086662)
		(mid 367.286043 -229.597148)
		(end 367.851436 -229.597204)
		(width 0.0889)
		(layer "In6.Cu")
		(net "DMI_CPU0_PCH_TX_DP<3>")
	)
	(arc
		(start 371.054122 -223.080834)
		(mid 371.185036 -222.944474)
		(end 371.232684 -222.761556)
		(width 0.0889)
		(layer "In6.Cu")
		(net "DMI_CPU0_PCH_TX_DP<3>")
	)
	(arc
		(start 362.965238 -227.653596)
		(mid 363.017508 -227.835961)
		(end 363.152436 -227.969318)
		(width 0.0889)
		(layer "In6.Cu")
		(net "DMI_CPU0_PCH_TX_DP<3>")
	)
	(arc
		(start 372.64213 -218.692222)
		(mid 372.716121 -218.412656)
		(end 372.918736 -218.20632)
		(width 0.0889)
		(layer "In6.Cu")
		(net "DMI_CPU0_PCH_TX_DP<3>")
	)
	(arc
		(start 370.583968 -223.894904)
		(mid 370.714882 -223.758544)
		(end 370.76253 -223.575626)
		(width 0.0889)
		(layer "In6.Cu")
		(net "DMI_CPU0_PCH_TX_DP<3>")
	)
	(arc
		(start 370.292884 -224.373948)
		(mid 370.372254 -224.100214)
		(end 370.575078 -223.899984)
		(width 0.0889)
		(layer "In6.Cu")
		(net "DMI_CPU0_PCH_TX_DP<3>")
	)
	(arc
		(start 373.864632 -214.947246)
		(mid 373.905445 -214.919943)
		(end 373.942356 -214.887556)
		(width 0.0889)
		(layer "In6.Cu")
		(net "DMI_CPU0_PCH_TX_DP<3>")
	)
	(arc
		(start 370.114322 -226.336606)
		(mid 370.245236 -226.200246)
		(end 370.292884 -226.017328)
		(width 0.0889)
		(layer "In6.Cu")
		(net "DMI_CPU0_PCH_TX_DP<3>")
	)
	(arc
		(start 373.58193 -215.436704)
		(mid 373.655921 -215.157138)
		(end 373.858536 -214.950802)
		(width 0.0889)
		(layer "In6.Cu")
		(net "DMI_CPU0_PCH_TX_DP<3>")
	)
	(arc
		(start 370.575078 -224.8789)
		(mid 370.372255 -224.678669)
		(end 370.292884 -224.404936)
		(width 0.0889)
		(layer "In6.Cu")
		(net "DMI_CPU0_PCH_TX_DP<3>")
	)
	(arc
		(start 367.851436 -229.597204)
		(mid 368.038634 -229.647347)
		(end 368.225832 -229.597204)
		(width 0.0889)
		(layer "In6.Cu")
		(net "DMI_CPU0_PCH_TX_DP<3>")
	)
	(arc
		(start 365.876078 -230.41102)
		(mid 366.150277 -230.335185)
		(end 366.42675 -230.402384)
		(width 0.0889)
		(layer "In6.Cu")
		(net "DMI_CPU0_PCH_TX_DP<3>")
	)
	(arc
		(start 372.463568 -219.0115)
		(mid 372.594482 -218.87514)
		(end 372.64213 -218.692222)
		(width 0.0889)
		(layer "In6.Cu")
		(net "DMI_CPU0_PCH_TX_DP<3>")
	)
	(arc
		(start 373.394732 -215.761062)
		(mid 373.529665 -215.627708)
		(end 373.58193 -215.44534)
		(width 0.0889)
		(layer "In6.Cu")
		(net "DMI_CPU0_PCH_TX_DP<3>")
	)
	(arc
		(start 363.628178 -228.786944)
		(mid 363.830765 -228.993295)
		(end 363.904784 -229.272846)
		(width 0.0889)
		(layer "In6.Cu")
		(net "DMI_CPU0_PCH_TX_DP<3>")
	)
	(arc
		(start 369.635532 -227.155502)
		(mid 369.770465 -227.022148)
		(end 369.82273 -226.83978)
		(width 0.0889)
		(layer "In6.Cu")
		(net "DMI_CPU0_PCH_TX_DP<3>")
	)
	(arc
		(start 364.092236 -229.597204)
		(mid 364.295059 -229.797435)
		(end 364.37443 -230.071168)
		(width 0.0889)
		(layer "In6.Cu")
		(net "DMI_CPU0_PCH_TX_DP<3>")
	)
	(arc
		(start 372.924832 -217.554048)
		(mid 372.641998 -217.071459)
		(end 372.91264 -216.58199)
		(width 0.0889)
		(layer "In6.Cu")
		(net "DMI_CPU0_PCH_TX_DP<3>")
	)
	(arc
		(start 364.936278 -230.41102)
		(mid 365.210477 -230.335185)
		(end 365.48695 -230.402384)
		(width 0.0889)
		(layer "In6.Cu")
		(net "DMI_CPU0_PCH_TX_DP<3>")
	)
	(arc
		(start 366.441482 -230.41102)
		(mid 366.815957 -230.410974)
		(end 367.00333 -230.086662)
		(width 0.0889)
		(layer "In6.Cu")
		(net "DMI_CPU0_PCH_TX_DP<3>")
	)
	(arc
		(start 371.993922 -219.825316)
		(mid 372.124836 -219.688956)
		(end 372.172484 -219.506038)
		(width 0.0889)
		(layer "In6.Cu")
		(net "DMI_CPU0_PCH_TX_DP<3>")
	)
	(arc
		(start 368.234722 -229.592124)
		(mid 368.365636 -229.455764)
		(end 368.413284 -229.272846)
		(width 0.0889)
		(layer "In6.Cu")
		(net "DMI_CPU0_PCH_TX_DP<3>")
	)
	(arc
		(start 369.82273 -226.831144)
		(mid 369.896721 -226.551578)
		(end 370.099336 -226.345242)
		(width 0.0889)
		(layer "In6.Cu")
		(net "DMI_CPU0_PCH_TX_DP<3>")
	)
	(arc
		(start 370.583968 -225.522536)
		(mid 370.711222 -225.39257)
		(end 370.762276 -225.21799)
		(width 0.0889)
		(layer "In6.Cu")
		(net "DMI_CPU0_PCH_TX_DP<3>")
	)
	(arc
		(start 369.165632 -227.969318)
		(mid 369.300565 -227.835964)
		(end 369.35283 -227.653596)
		(width 0.0889)
		(layer "In6.Cu")
		(net "DMI_CPU0_PCH_TX_DP<3>")
	)
	(arc
		(start 373.112284 -216.240614)
		(mid 373.190395 -215.963665)
		(end 373.394732 -215.761062)
		(width 0.0889)
		(layer "In6.Cu")
		(net "DMI_CPU0_PCH_TX_DP<3>")
	)
	(arc
		(start 371.993922 -221.453202)
		(mid 372.172519 -221.133924)
		(end 371.993922 -220.814646)
		(width 0.0889)
		(layer "In6.Cu")
		(net "DMI_CPU0_PCH_TX_DP<3>")
	)
	(arc
		(start 368.413284 -229.257352)
		(mid 368.492654 -228.983618)
		(end 368.695478 -228.783388)
		(width 0.0889)
		(layer "In6.Cu")
		(net "DMI_CPU0_PCH_TX_DP<3>")
	)
	(arc
		(start 372.933722 -218.197684)
		(mid 373.112319 -217.878406)
		(end 372.933722 -217.559128)
		(width 0.0889)
		(layer "In6.Cu")
		(net "DMI_CPU0_PCH_TX_DP<3>")
	)
	(arc
		(start 371.523768 -222.267018)
		(mid 371.654682 -222.130658)
		(end 371.70233 -221.94774)
		(width 0.0889)
		(layer "In6.Cu")
		(net "DMI_CPU0_PCH_TX_DP<3>")
	)
	(arc
		(start 364.561882 -230.41102)
		(mid 364.74908 -230.461163)
		(end 364.936278 -230.41102)
		(width 0.0889)
		(layer "In6.Cu")
		(net "DMI_CPU0_PCH_TX_DP<3>")
	)
	(arc
		(start 371.70233 -221.94774)
		(mid 371.776321 -221.668174)
		(end 371.978936 -221.461838)
		(width 0.0889)
		(layer "In6.Cu")
		(net "DMI_CPU0_PCH_TX_DP<3>")
	)
	(arc
		(start 363.904784 -229.272846)
		(mid 363.952463 -229.455746)
		(end 364.083346 -229.592124)
		(width 0.0889)
		(layer "In6.Cu")
		(net "DMI_CPU0_PCH_TX_DP<3>")
	)
	(arc
		(start 372.933722 -216.569798)
		(mid 373.064636 -216.433438)
		(end 373.112284 -216.25052)
		(width 0.0889)
		(layer "In6.Cu")
		(net "DMI_CPU0_PCH_TX_DP<3>")
	)
	(arc
		(start 368.704368 -228.778308)
		(mid 368.835282 -228.641948)
		(end 368.88293 -228.45903)
		(width 0.0889)
		(layer "In6.Cu")
		(net "DMI_CPU0_PCH_TX_DP<3>")
	)
	(arc
		(start 365.501682 -230.41102)
		(mid 365.68888 -230.461163)
		(end 365.876078 -230.41102)
		(width 0.0889)
		(layer "In6.Cu")
		(net "DMI_CPU0_PCH_TX_DP<3>")
	)
	(arc
		(start 362.7374 -227.191316)
		(mid 362.905154 -227.391094)
		(end 362.965238 -227.64496)
		(width 0.0889)
		(layer "In6.Cu")
		(net "DMI_CPU0_PCH_TX_DP<3>")
	)
	(arc
		(start 363.152436 -227.969318)
		(mid 363.353718 -228.166805)
		(end 363.43463 -228.436932)
		(width 0.0889)
		(layer "In6.Cu")
		(net "DMI_CPU0_PCH_TX_DP<3>")
	)
	(arc
		(start 372.172484 -219.490544)
		(mid 372.251854 -219.21681)
		(end 372.454678 -219.01658)
		(width 0.0889)
		(layer "In6.Cu")
		(net "DMI_CPU0_PCH_TX_DP<3>")
	)
	(arc
		(start 370.76253 -223.568006)
		(mid 370.840159 -223.289593)
		(end 371.045232 -223.085914)
		(width 0.0889)
		(layer "In6.Cu")
		(net "DMI_CPU0_PCH_TX_DP<3>")
	)
	(arc
		(start 371.70233 -220.319854)
		(mid 371.776321 -220.040288)
		(end 371.978936 -219.833952)
		(width 0.0889)
		(layer "In6.Cu")
		(net "DMI_CPU0_PCH_TX_DP<3>")
	)
	(arc
		(start 363.43463 -228.45903)
		(mid 363.482309 -228.64193)
		(end 363.613192 -228.778308)
		(width 0.0889)
		(layer "In6.Cu")
		(net "DMI_CPU0_PCH_TX_DP<3>")
	)
	(segment
		(start 347.025976 -70.866508)
		(end 346.596716 -70.437248)
		(width 0.13208)
		(layer "F.Cu")
		(net "DMI_CPU0_PCH_TX_DP<2>")
	)
	(segment
		(start 346.398596 -70.437248)
		(end 346.119196 -70.157848)
		(width 0.13208)
		(layer "F.Cu")
		(net "DMI_CPU0_PCH_TX_DP<2>")
	)
	(segment
		(start 346.119196 -69.964046)
		(end 345.79179 -69.63664)
		(width 0.13208)
		(layer "F.Cu")
		(net "DMI_CPU0_PCH_TX_DP<2>")
	)
	(segment
		(start 346.119196 -70.157848)
		(end 346.119196 -69.964046)
		(width 0.13208)
		(layer "F.Cu")
		(net "DMI_CPU0_PCH_TX_DP<2>")
	)
	(segment
		(start 346.741496 -71.816976)
		(end 347.025976 -71.532496)
		(width 0.13208)
		(layer "F.Cu")
		(net "DMI_CPU0_PCH_TX_DP<2>")
	)
	(segment
		(start 361.460034 -228.180646)
		(end 361.460034 -227.64496)
		(width 0.13208)
		(layer "F.Cu")
		(net "DMI_CPU0_PCH_TX_DP<2>")
	)
	(segment
		(start 346.596716 -70.437248)
		(end 346.398596 -70.437248)
		(width 0.13208)
		(layer "F.Cu")
		(net "DMI_CPU0_PCH_TX_DP<2>")
	)
	(segment
		(start 361.45978 -228.1809)
		(end 361.460034 -228.180646)
		(width 0.13208)
		(layer "F.Cu")
		(net "DMI_CPU0_PCH_TX_DP<2>")
	)
	(segment
		(start 347.025976 -71.532496)
		(end 347.025976 -70.866508)
		(width 0.13208)
		(layer "F.Cu")
		(net "DMI_CPU0_PCH_TX_DP<2>")
	)
	(segment
		(start 368.413284 -216.25052)
		(end 368.413284 -216.235026)
		(width 0.0889)
		(layer "In6.Cu")
		(net "DMI_CPU0_PCH_TX_DP<2>")
	)
	(segment
		(start 368.225832 -218.202764)
		(end 368.227356 -218.202002)
		(width 0.0889)
		(layer "In6.Cu")
		(net "DMI_CPU0_PCH_TX_DP<2>")
	)
	(segment
		(start 368.234722 -217.559128)
		(end 368.225832 -217.554048)
		(width 0.0889)
		(layer "In6.Cu")
		(net "DMI_CPU0_PCH_TX_DP<2>")
	)
	(segment
		(start 366.06353 -223.584262)
		(end 366.06353 -223.561402)
		(width 0.0889)
		(layer "In6.Cu")
		(net "DMI_CPU0_PCH_TX_DP<2>")
	)
	(segment
		(start 364.468156 -226.340924)
		(end 364.475522 -226.336606)
		(width 0.0889)
		(layer "In6.Cu")
		(net "DMI_CPU0_PCH_TX_DP<2>")
	)
	(segment
		(start 366.816894 -222.27159)
		(end 366.824768 -222.267018)
		(width 0.0889)
		(layer "In6.Cu")
		(net "DMI_CPU0_PCH_TX_DP<2>")
	)
	(segment
		(start 367.755678 -219.01658)
		(end 367.764568 -219.0115)
		(width 0.0889)
		(layer "In6.Cu")
		(net "DMI_CPU0_PCH_TX_DP<2>")
	)
	(segment
		(start 366.533684 -222.761556)
		(end 366.533684 -222.746062)
		(width 0.0889)
		(layer "In6.Cu")
		(net "DMI_CPU0_PCH_TX_DP<2>")
	)
	(segment
		(start 366.815878 -222.272098)
		(end 366.816894 -222.27159)
		(width 0.0889)
		(layer "In6.Cu")
		(net "DMI_CPU0_PCH_TX_DP<2>")
	)
	(segment
		(start 348.719902 -80.140302)
		(end 347.036136 -74.898504)
		(width 0.14732)
		(layer "In6.Cu")
		(net "DMI_CPU0_PCH_TX_DP<2>")
	)
	(segment
		(start 369.798854 -211.67725)
		(end 369.798854 -211.30641)
		(width 0.14732)
		(layer "In6.Cu")
		(net "DMI_CPU0_PCH_TX_DP<2>")
	)
	(segment
		(start 369.841018 -211.741512)
		(end 369.798854 -211.699348)
		(width 0.0889)
		(layer "In6.Cu")
		(net "DMI_CPU0_PCH_TX_DP<2>")
	)
	(segment
		(start 369.741958 -212.343492)
		(end 369.841018 -212.244432)
		(width 0.0889)
		(layer "In6.Cu")
		(net "DMI_CPU0_PCH_TX_DP<2>")
	)
	(segment
		(start 369.841018 -212.244432)
		(end 369.841018 -211.741512)
		(width 0.0889)
		(layer "In6.Cu")
		(net "DMI_CPU0_PCH_TX_DP<2>")
	)
	(segment
		(start 367.47323 -221.14256)
		(end 367.47323 -221.125288)
		(width 0.0889)
		(layer "In6.Cu")
		(net "DMI_CPU0_PCH_TX_DP<2>")
	)
	(segment
		(start 369.741958 -213.069932)
		(end 369.841018 -212.970872)
		(width 0.0889)
		(layer "In6.Cu")
		(net "DMI_CPU0_PCH_TX_DP<2>")
	)
	(segment
		(start 368.223038 -216.576402)
		(end 368.225832 -216.574878)
		(width 0.0889)
		(layer "In6.Cu")
		(net "DMI_CPU0_PCH_TX_DP<2>")
	)
	(segment
		(start 362.111036 -227.159058)
		(end 362.117132 -227.155502)
		(width 0.0889)
		(layer "In6.Cu")
		(net "DMI_CPU0_PCH_TX_DP<2>")
	)
	(segment
		(start 369.242594 -214.88781)
		(end 369.841018 -214.289386)
		(width 0.0889)
		(layer "In6.Cu")
		(net "DMI_CPU0_PCH_TX_DP<2>")
	)
	(segment
		(start 369.798854 -211.30641)
		(end 369.799108 -211.306156)
		(width 0.14732)
		(layer "In6.Cu")
		(net "DMI_CPU0_PCH_TX_DP<2>")
	)
	(segment
		(start 368.227356 -216.574116)
		(end 368.234722 -216.569798)
		(width 0.0889)
		(layer "In6.Cu")
		(net "DMI_CPU0_PCH_TX_DP<2>")
	)
	(segment
		(start 368.88293 -215.436704)
		(end 368.88293 -215.42121)
		(width 0.0889)
		(layer "In6.Cu")
		(net "DMI_CPU0_PCH_TX_DP<2>")
	)
	(segment
		(start 369.841018 -212.706712)
		(end 369.741958 -212.607652)
		(width 0.0889)
		(layer "In6.Cu")
		(net "DMI_CPU0_PCH_TX_DP<2>")
	)
	(segment
		(start 368.225832 -216.574878)
		(end 368.227356 -216.574116)
		(width 0.0889)
		(layer "In6.Cu")
		(net "DMI_CPU0_PCH_TX_DP<2>")
	)
	(segment
		(start 347.036136 -74.898504)
		(end 347.036136 -72.111616)
		(width 0.14732)
		(layer "In6.Cu")
		(net "DMI_CPU0_PCH_TX_DP<2>")
	)
	(segment
		(start 362.304584 -226.831144)
		(end 362.304584 -226.821238)
		(width 0.0889)
		(layer "In6.Cu")
		(net "DMI_CPU0_PCH_TX_DP<2>")
	)
	(segment
		(start 367.00333 -220.327474)
		(end 367.00333 -220.319854)
		(width 0.0889)
		(layer "In6.Cu")
		(net "DMI_CPU0_PCH_TX_DP<2>")
	)
	(segment
		(start 367.286032 -219.830396)
		(end 367.294922 -219.825316)
		(width 0.0889)
		(layer "In6.Cu")
		(net "DMI_CPU0_PCH_TX_DP<2>")
	)
	(segment
		(start 364.654084 -226.017328)
		(end 364.654084 -225.99523)
		(width 0.0889)
		(layer "In6.Cu")
		(net "DMI_CPU0_PCH_TX_DP<2>")
	)
	(segment
		(start 361.460034 -227.64496)
		(end 361.616498 -227.915978)
		(width 0.0889)
		(layer "In6.Cu")
		(net "DMI_CPU0_PCH_TX_DP<2>")
	)
	(segment
		(start 369.798854 -211.699348)
		(end 369.798854 -211.67725)
		(width 0.0889)
		(layer "In6.Cu")
		(net "DMI_CPU0_PCH_TX_DP<2>")
	)
	(segment
		(start 367.27384 -219.837508)
		(end 367.286032 -219.830396)
		(width 0.0889)
		(layer "In6.Cu")
		(net "DMI_CPU0_PCH_TX_DP<2>")
	)
	(segment
		(start 387.818122 -178.237134)
		(end 382.525016 -148.226272)
		(width 0.14732)
		(layer "In6.Cu")
		(net "DMI_CPU0_PCH_TX_DP<2>")
	)
	(segment
		(start 365.593884 -224.404936)
		(end 365.593884 -224.379536)
		(width 0.0889)
		(layer "In6.Cu")
		(net "DMI_CPU0_PCH_TX_DP<2>")
	)
	(segment
		(start 365.48695 -225.51898)
		(end 365.501682 -225.527616)
		(width 0.0889)
		(layer "In6.Cu")
		(net "DMI_CPU0_PCH_TX_DP<2>")
	)
	(segment
		(start 347.036136 -72.111616)
		(end 346.741496 -71.816976)
		(width 0.14732)
		(layer "In6.Cu")
		(net "DMI_CPU0_PCH_TX_DP<2>")
	)
	(segment
		(start 361.616498 -227.915978)
		(end 361.69473 -227.936806)
		(width 0.0889)
		(layer "In6.Cu")
		(net "DMI_CPU0_PCH_TX_DP<2>")
	)
	(segment
		(start 362.117132 -227.155502)
		(end 362.126022 -227.150422)
		(width 0.0889)
		(layer "In6.Cu")
		(net "DMI_CPU0_PCH_TX_DP<2>")
	)
	(segment
		(start 369.841018 -212.970872)
		(end 369.841018 -212.706712)
		(width 0.0889)
		(layer "In6.Cu")
		(net "DMI_CPU0_PCH_TX_DP<2>")
	)
	(segment
		(start 381.223012 -195.608956)
		(end 385.94411 -188.866526)
		(width 0.14732)
		(layer "In6.Cu")
		(net "DMI_CPU0_PCH_TX_DP<2>")
	)
	(segment
		(start 368.223038 -218.204288)
		(end 368.225832 -218.202764)
		(width 0.0889)
		(layer "In6.Cu")
		(net "DMI_CPU0_PCH_TX_DP<2>")
	)
	(segment
		(start 382.525016 -148.226272)
		(end 348.719902 -80.140302)
		(width 0.14732)
		(layer "In6.Cu")
		(net "DMI_CPU0_PCH_TX_DP<2>")
	)
	(segment
		(start 367.94313 -217.07856)
		(end 367.94313 -217.064336)
		(width 0.0889)
		(layer "In6.Cu")
		(net "DMI_CPU0_PCH_TX_DP<2>")
	)
	(segment
		(start 365.884968 -224.88398)
		(end 365.876078 -224.8789)
		(width 0.0889)
		(layer "In6.Cu")
		(net "DMI_CPU0_PCH_TX_DP<2>")
	)
	(segment
		(start 370.119148 -207.612234)
		(end 375.090436 -200.513188)
		(width 0.14732)
		(layer "In6.Cu")
		(net "DMI_CPU0_PCH_TX_DP<2>")
	)
	(segment
		(start 367.27384 -221.465394)
		(end 367.286032 -221.458282)
		(width 0.0889)
		(layer "In6.Cu")
		(net "DMI_CPU0_PCH_TX_DP<2>")
	)
	(segment
		(start 369.841018 -214.289386)
		(end 369.841018 -213.433152)
		(width 0.0889)
		(layer "In6.Cu")
		(net "DMI_CPU0_PCH_TX_DP<2>")
	)
	(segment
		(start 375.090436 -200.513188)
		(end 379.187456 -197.644766)
		(width 0.14732)
		(layer "In6.Cu")
		(net "DMI_CPU0_PCH_TX_DP<2>")
	)
	(segment
		(start 369.799108 -209.431636)
		(end 370.119148 -207.612234)
		(width 0.14732)
		(layer "In6.Cu")
		(net "DMI_CPU0_PCH_TX_DP<2>")
	)
	(segment
		(start 385.94411 -188.866526)
		(end 387.818122 -178.237134)
		(width 0.14732)
		(layer "In6.Cu")
		(net "DMI_CPU0_PCH_TX_DP<2>")
	)
	(segment
		(start 379.187456 -197.644766)
		(end 381.223012 -195.608956)
		(width 0.14732)
		(layer "In6.Cu")
		(net "DMI_CPU0_PCH_TX_DP<2>")
	)
	(segment
		(start 368.227356 -218.202002)
		(end 368.234722 -218.197684)
		(width 0.0889)
		(layer "In6.Cu")
		(net "DMI_CPU0_PCH_TX_DP<2>")
	)
	(segment
		(start 369.841018 -213.433152)
		(end 369.741958 -213.334092)
		(width 0.0889)
		(layer "In6.Cu")
		(net "DMI_CPU0_PCH_TX_DP<2>")
	)
	(segment
		(start 368.219736 -218.20632)
		(end 368.223038 -218.204288)
		(width 0.0889)
		(layer "In6.Cu")
		(net "DMI_CPU0_PCH_TX_DP<2>")
	)
	(segment
		(start 365.876078 -225.527616)
		(end 365.884968 -225.522536)
		(width 0.0889)
		(layer "In6.Cu")
		(net "DMI_CPU0_PCH_TX_DP<2>")
	)
	(segment
		(start 368.219736 -216.578434)
		(end 368.223038 -216.576402)
		(width 0.0889)
		(layer "In6.Cu")
		(net "DMI_CPU0_PCH_TX_DP<2>")
	)
	(segment
		(start 364.466632 -226.341686)
		(end 364.468156 -226.340924)
		(width 0.0889)
		(layer "In6.Cu")
		(net "DMI_CPU0_PCH_TX_DP<2>")
	)
	(segment
		(start 366.346232 -223.085914)
		(end 366.355122 -223.080834)
		(width 0.0889)
		(layer "In6.Cu")
		(net "DMI_CPU0_PCH_TX_DP<2>")
	)
	(segment
		(start 369.799108 -211.306156)
		(end 369.799108 -209.431636)
		(width 0.14732)
		(layer "In6.Cu")
		(net "DMI_CPU0_PCH_TX_DP<2>")
	)
	(segment
		(start 368.695478 -215.761062)
		(end 368.704368 -215.755982)
		(width 0.0889)
		(layer "In6.Cu")
		(net "DMI_CPU0_PCH_TX_DP<2>")
	)
	(segment
		(start 369.741958 -212.607652)
		(end 369.741958 -212.343492)
		(width 0.0889)
		(layer "In6.Cu")
		(net "DMI_CPU0_PCH_TX_DP<2>")
	)
	(segment
		(start 367.473484 -219.506038)
		(end 367.473484 -219.490544)
		(width 0.0889)
		(layer "In6.Cu")
		(net "DMI_CPU0_PCH_TX_DP<2>")
	)
	(segment
		(start 369.741958 -213.334092)
		(end 369.741958 -213.069932)
		(width 0.0889)
		(layer "In6.Cu")
		(net "DMI_CPU0_PCH_TX_DP<2>")
	)
	(arc
		(start 367.286032 -220.809566)
		(mid 367.08096 -220.605887)
		(end 367.00333 -220.327474)
		(width 0.0889)
		(layer "In6.Cu")
		(net "DMI_CPU0_PCH_TX_DP<2>")
	)
	(arc
		(start 367.473484 -219.490544)
		(mid 367.552854 -219.21681)
		(end 367.755678 -219.01658)
		(width 0.0889)
		(layer "In6.Cu")
		(net "DMI_CPU0_PCH_TX_DP<2>")
	)
	(arc
		(start 367.94313 -218.692222)
		(mid 368.017121 -218.412656)
		(end 368.219736 -218.20632)
		(width 0.0889)
		(layer "In6.Cu")
		(net "DMI_CPU0_PCH_TX_DP<2>")
	)
	(arc
		(start 368.88293 -215.42121)
		(mid 368.9623 -215.147476)
		(end 369.165124 -214.947246)
		(width 0.0889)
		(layer "In6.Cu")
		(net "DMI_CPU0_PCH_TX_DP<2>")
	)
	(arc
		(start 369.165124 -214.947246)
		(mid 369.205794 -214.920052)
		(end 369.242594 -214.88781)
		(width 0.0889)
		(layer "In6.Cu")
		(net "DMI_CPU0_PCH_TX_DP<2>")
	)
	(arc
		(start 368.234722 -216.569798)
		(mid 368.365636 -216.433438)
		(end 368.413284 -216.25052)
		(width 0.0889)
		(layer "In6.Cu")
		(net "DMI_CPU0_PCH_TX_DP<2>")
	)
	(arc
		(start 366.063276 -225.21799)
		(mid 366.063473 -225.210625)
		(end 366.06353 -225.203258)
		(width 0.0889)
		(layer "In6.Cu")
		(net "DMI_CPU0_PCH_TX_DP<2>")
	)
	(arc
		(start 366.533684 -222.746062)
		(mid 366.613054 -222.472328)
		(end 366.815878 -222.272098)
		(width 0.0889)
		(layer "In6.Cu")
		(net "DMI_CPU0_PCH_TX_DP<2>")
	)
	(arc
		(start 366.06353 -225.203258)
		(mid 366.015851 -225.020358)
		(end 365.884968 -224.88398)
		(width 0.0889)
		(layer "In6.Cu")
		(net "DMI_CPU0_PCH_TX_DP<2>")
	)
	(arc
		(start 365.876078 -224.8789)
		(mid 365.673255 -224.678669)
		(end 365.593884 -224.404936)
		(width 0.0889)
		(layer "In6.Cu")
		(net "DMI_CPU0_PCH_TX_DP<2>")
	)
	(arc
		(start 365.501682 -225.527616)
		(mid 365.68888 -225.577759)
		(end 365.876078 -225.527616)
		(width 0.0889)
		(layer "In6.Cu")
		(net "DMI_CPU0_PCH_TX_DP<2>")
	)
	(arc
		(start 367.00333 -221.94774)
		(mid 367.075565 -221.671216)
		(end 367.27384 -221.465394)
		(width 0.0889)
		(layer "In6.Cu")
		(net "DMI_CPU0_PCH_TX_DP<2>")
	)
	(arc
		(start 362.304584 -226.821238)
		(mid 362.382695 -226.544289)
		(end 362.587032 -226.341686)
		(width 0.0889)
		(layer "In6.Cu")
		(net "DMI_CPU0_PCH_TX_DP<2>")
	)
	(arc
		(start 368.413284 -216.235026)
		(mid 368.492654 -215.961292)
		(end 368.695478 -215.761062)
		(width 0.0889)
		(layer "In6.Cu")
		(net "DMI_CPU0_PCH_TX_DP<2>")
	)
	(arc
		(start 365.593884 -224.379536)
		(mid 365.671995 -224.102587)
		(end 365.876332 -223.899984)
		(width 0.0889)
		(layer "In6.Cu")
		(net "DMI_CPU0_PCH_TX_DP<2>")
	)
	(arc
		(start 361.834684 -227.64496)
		(mid 361.9086 -227.365458)
		(end 362.111036 -227.159058)
		(width 0.0889)
		(layer "In6.Cu")
		(net "DMI_CPU0_PCH_TX_DP<2>")
	)
	(arc
		(start 363.152436 -226.341686)
		(mid 363.339634 -226.391829)
		(end 363.526832 -226.341686)
		(width 0.0889)
		(layer "In6.Cu")
		(net "DMI_CPU0_PCH_TX_DP<2>")
	)
	(arc
		(start 367.294922 -219.825316)
		(mid 367.425836 -219.688956)
		(end 367.473484 -219.506038)
		(width 0.0889)
		(layer "In6.Cu")
		(net "DMI_CPU0_PCH_TX_DP<2>")
	)
	(arc
		(start 361.69473 -227.936806)
		(mid 361.797875 -227.806781)
		(end 361.834684 -227.64496)
		(width 0.0889)
		(layer "In6.Cu")
		(net "DMI_CPU0_PCH_TX_DP<2>")
	)
	(arc
		(start 363.526832 -226.341686)
		(mid 363.809534 -226.26591)
		(end 364.092236 -226.341686)
		(width 0.0889)
		(layer "In6.Cu")
		(net "DMI_CPU0_PCH_TX_DP<2>")
	)
	(arc
		(start 364.936278 -225.527616)
		(mid 365.210507 -225.451691)
		(end 365.48695 -225.51898)
		(width 0.0889)
		(layer "In6.Cu")
		(net "DMI_CPU0_PCH_TX_DP<2>")
	)
	(arc
		(start 362.587032 -226.341686)
		(mid 362.869734 -226.26591)
		(end 363.152436 -226.341686)
		(width 0.0889)
		(layer "In6.Cu")
		(net "DMI_CPU0_PCH_TX_DP<2>")
	)
	(arc
		(start 367.94313 -217.064336)
		(mid 368.017121 -216.78477)
		(end 368.219736 -216.578434)
		(width 0.0889)
		(layer "In6.Cu")
		(net "DMI_CPU0_PCH_TX_DP<2>")
	)
	(arc
		(start 364.654084 -225.99523)
		(mid 364.734995 -225.725102)
		(end 364.936278 -225.527616)
		(width 0.0889)
		(layer "In6.Cu")
		(net "DMI_CPU0_PCH_TX_DP<2>")
	)
	(arc
		(start 365.884968 -225.522536)
		(mid 366.012222 -225.39257)
		(end 366.063276 -225.21799)
		(width 0.0889)
		(layer "In6.Cu")
		(net "DMI_CPU0_PCH_TX_DP<2>")
	)
	(arc
		(start 367.764568 -219.0115)
		(mid 367.895482 -218.87514)
		(end 367.94313 -218.692222)
		(width 0.0889)
		(layer "In6.Cu")
		(net "DMI_CPU0_PCH_TX_DP<2>")
	)
	(arc
		(start 366.824768 -222.267018)
		(mid 366.955682 -222.130658)
		(end 367.00333 -221.94774)
		(width 0.0889)
		(layer "In6.Cu")
		(net "DMI_CPU0_PCH_TX_DP<2>")
	)
	(arc
		(start 362.126022 -227.150422)
		(mid 362.256936 -227.014062)
		(end 362.304584 -226.831144)
		(width 0.0889)
		(layer "In6.Cu")
		(net "DMI_CPU0_PCH_TX_DP<2>")
	)
	(arc
		(start 368.234722 -218.197684)
		(mid 368.413319 -217.878406)
		(end 368.234722 -217.559128)
		(width 0.0889)
		(layer "In6.Cu")
		(net "DMI_CPU0_PCH_TX_DP<2>")
	)
	(arc
		(start 366.355122 -223.080834)
		(mid 366.486036 -222.944474)
		(end 366.533684 -222.761556)
		(width 0.0889)
		(layer "In6.Cu")
		(net "DMI_CPU0_PCH_TX_DP<2>")
	)
	(arc
		(start 364.092236 -226.341686)
		(mid 364.279434 -226.391829)
		(end 364.466632 -226.341686)
		(width 0.0889)
		(layer "In6.Cu")
		(net "DMI_CPU0_PCH_TX_DP<2>")
	)
	(arc
		(start 368.704368 -215.755982)
		(mid 368.835282 -215.619622)
		(end 368.88293 -215.436704)
		(width 0.0889)
		(layer "In6.Cu")
		(net "DMI_CPU0_PCH_TX_DP<2>")
	)
	(arc
		(start 365.876332 -223.899984)
		(mid 366.011265 -223.76663)
		(end 366.06353 -223.584262)
		(width 0.0889)
		(layer "In6.Cu")
		(net "DMI_CPU0_PCH_TX_DP<2>")
	)
	(arc
		(start 366.06353 -223.561402)
		(mid 366.142749 -223.286717)
		(end 366.346232 -223.085914)
		(width 0.0889)
		(layer "In6.Cu")
		(net "DMI_CPU0_PCH_TX_DP<2>")
	)
	(arc
		(start 367.47323 -221.125288)
		(mid 367.42096 -220.942923)
		(end 367.286032 -220.809566)
		(width 0.0889)
		(layer "In6.Cu")
		(net "DMI_CPU0_PCH_TX_DP<2>")
	)
	(arc
		(start 364.475522 -226.336606)
		(mid 364.606436 -226.200246)
		(end 364.654084 -226.017328)
		(width 0.0889)
		(layer "In6.Cu")
		(net "DMI_CPU0_PCH_TX_DP<2>")
	)
	(arc
		(start 367.286032 -221.458282)
		(mid 367.420965 -221.324928)
		(end 367.47323 -221.14256)
		(width 0.0889)
		(layer "In6.Cu")
		(net "DMI_CPU0_PCH_TX_DP<2>")
	)
	(arc
		(start 367.00333 -220.319854)
		(mid 367.075565 -220.04333)
		(end 367.27384 -219.837508)
		(width 0.0889)
		(layer "In6.Cu")
		(net "DMI_CPU0_PCH_TX_DP<2>")
	)
	(arc
		(start 368.225832 -217.554048)
		(mid 368.022351 -217.353244)
		(end 367.94313 -217.07856)
		(width 0.0889)
		(layer "In6.Cu")
		(net "DMI_CPU0_PCH_TX_DP<2>")
	)
	(segment
		(start 344.541856 -71.880222)
		(end 344.541856 -71.984616)
		(width 0.13208)
		(layer "F.Cu")
		(net "DMI_CPU0_PCH_TX_DP<1>")
	)
	(segment
		(start 343.73439 -70.78726)
		(end 344.06205 -71.11492)
		(width 0.13208)
		(layer "F.Cu")
		(net "DMI_CPU0_PCH_TX_DP<1>")
	)
	(segment
		(start 344.06205 -71.400416)
		(end 344.541856 -71.880222)
		(width 0.13208)
		(layer "F.Cu")
		(net "DMI_CPU0_PCH_TX_DP<1>")
	)
	(segment
		(start 344.06205 -71.11492)
		(end 344.06205 -71.400416)
		(width 0.13208)
		(layer "F.Cu")
		(net "DMI_CPU0_PCH_TX_DP<1>")
	)
	(segment
		(start 360.98988 -227.36683)
		(end 360.98988 -226.831144)
		(width 0.13208)
		(layer "F.Cu")
		(net "DMI_CPU0_PCH_TX_DP<1>")
	)
	(segment
		(start 344.541856 -71.984616)
		(end 344.226896 -72.299576)
		(width 0.13208)
		(layer "F.Cu")
		(net "DMI_CPU0_PCH_TX_DP<1>")
	)
	(segment
		(start 360.990134 -227.367084)
		(end 360.98988 -227.36683)
		(width 0.13208)
		(layer "F.Cu")
		(net "DMI_CPU0_PCH_TX_DP<1>")
	)
	(segment
		(start 369.181126 -207.304386)
		(end 374.32107 -199.964294)
		(width 0.14732)
		(layer "In6.Cu")
		(net "DMI_CPU0_PCH_TX_DP<1>")
	)
	(segment
		(start 366.06353 -220.334078)
		(end 366.06353 -220.319854)
		(width 0.0889)
		(layer "In6.Cu")
		(net "DMI_CPU0_PCH_TX_DP<1>")
	)
	(segment
		(start 368.764566 -213.464394)
		(end 368.863626 -213.365334)
		(width 0.0889)
		(layer "In6.Cu")
		(net "DMI_CPU0_PCH_TX_DP<1>")
	)
	(segment
		(start 364.937294 -223.899476)
		(end 364.945168 -223.894904)
		(width 0.0889)
		(layer "In6.Cu")
		(net "DMI_CPU0_PCH_TX_DP<1>")
	)
	(segment
		(start 344.976196 -75.41641)
		(end 345.053158 -75.262232)
		(width 0.14732)
		(layer "In6.Cu")
		(net "DMI_CPU0_PCH_TX_DP<1>")
	)
	(segment
		(start 361.177078 -227.155502)
		(end 361.178094 -227.154994)
		(width 0.0889)
		(layer "In6.Cu")
		(net "DMI_CPU0_PCH_TX_DP<1>")
	)
	(segment
		(start 378.83719 -196.802248)
		(end 380.57074 -195.068444)
		(width 0.14732)
		(layer "In6.Cu")
		(net "DMI_CPU0_PCH_TX_DP<1>")
	)
	(segment
		(start 367.29289 -218.198954)
		(end 367.294922 -218.197684)
		(width 0.0889)
		(layer "In6.Cu")
		(net "DMI_CPU0_PCH_TX_DP<1>")
	)
	(segment
		(start 363.60735 -225.51898)
		(end 363.622082 -225.527616)
		(width 0.0889)
		(layer "In6.Cu")
		(net "DMI_CPU0_PCH_TX_DP<1>")
	)
	(segment
		(start 366.355122 -220.814646)
		(end 366.346232 -220.809566)
		(width 0.0889)
		(layer "In6.Cu")
		(net "DMI_CPU0_PCH_TX_DP<1>")
	)
	(segment
		(start 344.760804 -74.770742)
		(end 344.622628 -74.356214)
		(width 0.14732)
		(layer "In6.Cu")
		(net "DMI_CPU0_PCH_TX_DP<1>")
	)
	(segment
		(start 367.293652 -218.198446)
		(end 367.29289 -218.198954)
		(width 0.0889)
		(layer "In6.Cu")
		(net "DMI_CPU0_PCH_TX_DP<1>")
	)
	(segment
		(start 386.871718 -178.111658)
		(end 381.721868 -148.907754)
		(width 0.14732)
		(layer "In6.Cu")
		(net "DMI_CPU0_PCH_TX_DP<1>")
	)
	(segment
		(start 367.94313 -215.44534)
		(end 367.94313 -215.436704)
		(width 0.0889)
		(layer "In6.Cu")
		(net "DMI_CPU0_PCH_TX_DP<1>")
	)
	(segment
		(start 367.27384 -216.58199)
		(end 367.294922 -216.569798)
		(width 0.0889)
		(layer "In6.Cu")
		(net "DMI_CPU0_PCH_TX_DP<1>")
	)
	(segment
		(start 366.353852 -221.453964)
		(end 366.35309 -221.454472)
		(width 0.0889)
		(layer "In6.Cu")
		(net "DMI_CPU0_PCH_TX_DP<1>")
	)
	(segment
		(start 368.821462 -211.69503)
		(end 368.821462 -209.346038)
		(width 0.14732)
		(layer "In6.Cu")
		(net "DMI_CPU0_PCH_TX_DP<1>")
	)
	(segment
		(start 361.63504 -226.348798)
		(end 361.647232 -226.341686)
		(width 0.0889)
		(layer "In6.Cu")
		(net "DMI_CPU0_PCH_TX_DP<1>")
	)
	(segment
		(start 345.114118 -75.831192)
		(end 344.976196 -75.41641)
		(width 0.14732)
		(layer "In6.Cu")
		(net "DMI_CPU0_PCH_TX_DP<1>")
	)
	(segment
		(start 368.863626 -212.611208)
		(end 368.863626 -211.759292)
		(width 0.0889)
		(layer "In6.Cu")
		(net "DMI_CPU0_PCH_TX_DP<1>")
	)
	(segment
		(start 345.26855 -75.908408)
		(end 345.114118 -75.831192)
		(width 0.14732)
		(layer "In6.Cu")
		(net "DMI_CPU0_PCH_TX_DP<1>")
	)
	(segment
		(start 344.521536 -73.666604)
		(end 344.521536 -72.594216)
		(width 0.14732)
		(layer "In6.Cu")
		(net "DMI_CPU0_PCH_TX_DP<1>")
	)
	(segment
		(start 363.996478 -225.527616)
		(end 364.005368 -225.522536)
		(width 0.0889)
		(layer "In6.Cu")
		(net "DMI_CPU0_PCH_TX_DP<1>")
	)
	(segment
		(start 366.35309 -221.454472)
		(end 366.355122 -221.453202)
		(width 0.0889)
		(layer "In6.Cu")
		(net "DMI_CPU0_PCH_TX_DP<1>")
	)
	(segment
		(start 364.654084 -224.389442)
		(end 364.654084 -224.373948)
		(width 0.0889)
		(layer "In6.Cu")
		(net "DMI_CPU0_PCH_TX_DP<1>")
	)
	(segment
		(start 361.834684 -226.017328)
		(end 361.834684 -225.99523)
		(width 0.0889)
		(layer "In6.Cu")
		(net "DMI_CPU0_PCH_TX_DP<1>")
	)
	(segment
		(start 344.622628 -74.356214)
		(end 344.699844 -74.202036)
		(width 0.14732)
		(layer "In6.Cu")
		(net "DMI_CPU0_PCH_TX_DP<1>")
	)
	(segment
		(start 347.159834 -81.5848)
		(end 345.26855 -75.908408)
		(width 0.14732)
		(layer "In6.Cu")
		(net "DMI_CPU0_PCH_TX_DP<1>")
	)
	(segment
		(start 365.12373 -223.575626)
		(end 365.12373 -223.568006)
		(width 0.0889)
		(layer "In6.Cu")
		(net "DMI_CPU0_PCH_TX_DP<1>")
	)
	(segment
		(start 360.98988 -226.831144)
		(end 360.833416 -227.102162)
		(width 0.0889)
		(layer "In6.Cu")
		(net "DMI_CPU0_PCH_TX_DP<1>")
	)
	(segment
		(start 364.474252 -224.709482)
		(end 364.47349 -224.70999)
		(width 0.0889)
		(layer "In6.Cu")
		(net "DMI_CPU0_PCH_TX_DP<1>")
	)
	(segment
		(start 368.303556 -214.887556)
		(end 368.863626 -214.327486)
		(width 0.0889)
		(layer "In6.Cu")
		(net "DMI_CPU0_PCH_TX_DP<1>")
	)
	(segment
		(start 367.473484 -216.25052)
		(end 367.473484 -216.240614)
		(width 0.0889)
		(layer "In6.Cu")
		(net "DMI_CPU0_PCH_TX_DP<1>")
	)
	(segment
		(start 366.340136 -219.833952)
		(end 366.344962 -219.831158)
		(width 0.0889)
		(layer "In6.Cu")
		(net "DMI_CPU0_PCH_TX_DP<1>")
	)
	(segment
		(start 364.47349 -224.70999)
		(end 364.475522 -224.70872)
		(width 0.0889)
		(layer "In6.Cu")
		(net "DMI_CPU0_PCH_TX_DP<1>")
	)
	(segment
		(start 367.286794 -217.554556)
		(end 367.286032 -217.554048)
		(width 0.0889)
		(layer "In6.Cu")
		(net "DMI_CPU0_PCH_TX_DP<1>")
	)
	(segment
		(start 345.053158 -75.262232)
		(end 344.915236 -74.847958)
		(width 0.14732)
		(layer "In6.Cu")
		(net "DMI_CPU0_PCH_TX_DP<1>")
	)
	(segment
		(start 381.721868 -148.907754)
		(end 347.159834 -81.5848)
		(width 0.14732)
		(layer "In6.Cu")
		(net "DMI_CPU0_PCH_TX_DP<1>")
	)
	(segment
		(start 366.355122 -219.825062)
		(end 366.355122 -219.825316)
		(width 0.0889)
		(layer "In6.Cu")
		(net "DMI_CPU0_PCH_TX_DP<1>")
	)
	(segment
		(start 361.178094 -227.154994)
		(end 361.185968 -227.150422)
		(width 0.0889)
		(layer "In6.Cu")
		(net "DMI_CPU0_PCH_TX_DP<1>")
	)
	(segment
		(start 360.833416 -227.102162)
		(end 360.854498 -227.18014)
		(width 0.0889)
		(layer "In6.Cu")
		(net "DMI_CPU0_PCH_TX_DP<1>")
	)
	(segment
		(start 367.294922 -217.559128)
		(end 367.286794 -217.554556)
		(width 0.0889)
		(layer "In6.Cu")
		(net "DMI_CPU0_PCH_TX_DP<1>")
	)
	(segment
		(start 368.863626 -211.759292)
		(end 368.821462 -211.717128)
		(width 0.0889)
		(layer "In6.Cu")
		(net "DMI_CPU0_PCH_TX_DP<1>")
	)
	(segment
		(start 366.347248 -219.829634)
		(end 366.355122 -219.825062)
		(width 0.0889)
		(layer "In6.Cu")
		(net "DMI_CPU0_PCH_TX_DP<1>")
	)
	(segment
		(start 366.340136 -221.461838)
		(end 366.353852 -221.453964)
		(width 0.0889)
		(layer "In6.Cu")
		(net "DMI_CPU0_PCH_TX_DP<1>")
	)
	(segment
		(start 364.460536 -224.717356)
		(end 364.474252 -224.709482)
		(width 0.0889)
		(layer "In6.Cu")
		(net "DMI_CPU0_PCH_TX_DP<1>")
	)
	(segment
		(start 364.936278 -223.899984)
		(end 364.937294 -223.899476)
		(width 0.0889)
		(layer "In6.Cu")
		(net "DMI_CPU0_PCH_TX_DP<1>")
	)
	(segment
		(start 365.876078 -222.272098)
		(end 365.884968 -222.267018)
		(width 0.0889)
		(layer "In6.Cu")
		(net "DMI_CPU0_PCH_TX_DP<1>")
	)
	(segment
		(start 368.863626 -213.365334)
		(end 368.863626 -213.073488)
		(width 0.0889)
		(layer "In6.Cu")
		(net "DMI_CPU0_PCH_TX_DP<1>")
	)
	(segment
		(start 368.764566 -213.728554)
		(end 368.764566 -213.464394)
		(width 0.0889)
		(layer "In6.Cu")
		(net "DMI_CPU0_PCH_TX_DP<1>")
	)
	(segment
		(start 366.815878 -219.01658)
		(end 366.824768 -219.0115)
		(width 0.0889)
		(layer "In6.Cu")
		(net "DMI_CPU0_PCH_TX_DP<1>")
	)
	(segment
		(start 368.764566 -212.974428)
		(end 368.764566 -212.710268)
		(width 0.0889)
		(layer "In6.Cu")
		(net "DMI_CPU0_PCH_TX_DP<1>")
	)
	(segment
		(start 368.821462 -211.717128)
		(end 368.821462 -211.69503)
		(width 0.0889)
		(layer "In6.Cu")
		(net "DMI_CPU0_PCH_TX_DP<1>")
	)
	(segment
		(start 380.57074 -195.068444)
		(end 384.99669 -188.7474)
		(width 0.14732)
		(layer "In6.Cu")
		(net "DMI_CPU0_PCH_TX_DP<1>")
	)
	(segment
		(start 344.699844 -74.202036)
		(end 344.521536 -73.666604)
		(width 0.14732)
		(layer "In6.Cu")
		(net "DMI_CPU0_PCH_TX_DP<1>")
	)
	(segment
		(start 368.863626 -214.327486)
		(end 368.863626 -213.827614)
		(width 0.0889)
		(layer "In6.Cu")
		(net "DMI_CPU0_PCH_TX_DP<1>")
	)
	(segment
		(start 344.521536 -72.594216)
		(end 344.226896 -72.299576)
		(width 0.14732)
		(layer "In6.Cu")
		(net "DMI_CPU0_PCH_TX_DP<1>")
	)
	(segment
		(start 367.279936 -218.20632)
		(end 367.293652 -218.198446)
		(width 0.0889)
		(layer "In6.Cu")
		(net "DMI_CPU0_PCH_TX_DP<1>")
	)
	(segment
		(start 361.647232 -226.341686)
		(end 361.656122 -226.336606)
		(width 0.0889)
		(layer "In6.Cu")
		(net "DMI_CPU0_PCH_TX_DP<1>")
	)
	(segment
		(start 365.593884 -222.761556)
		(end 365.593884 -222.746062)
		(width 0.0889)
		(layer "In6.Cu")
		(net "DMI_CPU0_PCH_TX_DP<1>")
	)
	(segment
		(start 366.344962 -219.831158)
		(end 366.347248 -219.829634)
		(width 0.0889)
		(layer "In6.Cu")
		(net "DMI_CPU0_PCH_TX_DP<1>")
	)
	(segment
		(start 368.863626 -213.827614)
		(end 368.764566 -213.728554)
		(width 0.0889)
		(layer "In6.Cu")
		(net "DMI_CPU0_PCH_TX_DP<1>")
	)
	(segment
		(start 366.533684 -219.506038)
		(end 366.533684 -219.490544)
		(width 0.0889)
		(layer "In6.Cu")
		(net "DMI_CPU0_PCH_TX_DP<1>")
	)
	(segment
		(start 384.99669 -188.7474)
		(end 386.871718 -178.111658)
		(width 0.14732)
		(layer "In6.Cu")
		(net "DMI_CPU0_PCH_TX_DP<1>")
	)
	(segment
		(start 367.00333 -217.071956)
		(end 367.00333 -217.064336)
		(width 0.0889)
		(layer "In6.Cu")
		(net "DMI_CPU0_PCH_TX_DP<1>")
	)
	(segment
		(start 368.821462 -209.346038)
		(end 369.181126 -207.304386)
		(width 0.14732)
		(layer "In6.Cu")
		(net "DMI_CPU0_PCH_TX_DP<1>")
	)
	(segment
		(start 368.219736 -214.950802)
		(end 368.225832 -214.947246)
		(width 0.0889)
		(layer "In6.Cu")
		(net "DMI_CPU0_PCH_TX_DP<1>")
	)
	(segment
		(start 374.32107 -199.964294)
		(end 378.83719 -196.802248)
		(width 0.14732)
		(layer "In6.Cu")
		(net "DMI_CPU0_PCH_TX_DP<1>")
	)
	(segment
		(start 368.863626 -213.073488)
		(end 368.764566 -212.974428)
		(width 0.0889)
		(layer "In6.Cu")
		(net "DMI_CPU0_PCH_TX_DP<1>")
	)
	(segment
		(start 368.764566 -212.710268)
		(end 368.863626 -212.611208)
		(width 0.0889)
		(layer "In6.Cu")
		(net "DMI_CPU0_PCH_TX_DP<1>")
	)
	(segment
		(start 365.406432 -223.085914)
		(end 365.415322 -223.080834)
		(width 0.0889)
		(layer "In6.Cu")
		(net "DMI_CPU0_PCH_TX_DP<1>")
	)
	(segment
		(start 362.66755 -225.51898)
		(end 362.682282 -225.527616)
		(width 0.0889)
		(layer "In6.Cu")
		(net "DMI_CPU0_PCH_TX_DP<1>")
	)
	(segment
		(start 344.915236 -74.847958)
		(end 344.760804 -74.770742)
		(width 0.14732)
		(layer "In6.Cu")
		(net "DMI_CPU0_PCH_TX_DP<1>")
	)
	(arc
		(start 364.18393 -225.203258)
		(mid 364.257921 -224.923692)
		(end 364.460536 -224.717356)
		(width 0.0889)
		(layer "In6.Cu")
		(net "DMI_CPU0_PCH_TX_DP<1>")
	)
	(arc
		(start 366.06353 -221.94774)
		(mid 366.137521 -221.668174)
		(end 366.340136 -221.461838)
		(width 0.0889)
		(layer "In6.Cu")
		(net "DMI_CPU0_PCH_TX_DP<1>")
	)
	(arc
		(start 367.94313 -215.436704)
		(mid 368.017121 -215.157138)
		(end 368.219736 -214.950802)
		(width 0.0889)
		(layer "In6.Cu")
		(net "DMI_CPU0_PCH_TX_DP<1>")
	)
	(arc
		(start 361.834684 -225.99523)
		(mid 361.915595 -225.725102)
		(end 362.116878 -225.527616)
		(width 0.0889)
		(layer "In6.Cu")
		(net "DMI_CPU0_PCH_TX_DP<1>")
	)
	(arc
		(start 362.682282 -225.527616)
		(mid 362.86948 -225.577759)
		(end 363.056678 -225.527616)
		(width 0.0889)
		(layer "In6.Cu")
		(net "DMI_CPU0_PCH_TX_DP<1>")
	)
	(arc
		(start 367.00333 -217.064336)
		(mid 367.075565 -216.787812)
		(end 367.27384 -216.58199)
		(width 0.0889)
		(layer "In6.Cu")
		(net "DMI_CPU0_PCH_TX_DP<1>")
	)
	(arc
		(start 367.755932 -215.761062)
		(mid 367.890865 -215.627708)
		(end 367.94313 -215.44534)
		(width 0.0889)
		(layer "In6.Cu")
		(net "DMI_CPU0_PCH_TX_DP<1>")
	)
	(arc
		(start 367.00333 -218.692222)
		(mid 367.077321 -218.412656)
		(end 367.279936 -218.20632)
		(width 0.0889)
		(layer "In6.Cu")
		(net "DMI_CPU0_PCH_TX_DP<1>")
	)
	(arc
		(start 364.475522 -224.70872)
		(mid 364.606436 -224.57236)
		(end 364.654084 -224.389442)
		(width 0.0889)
		(layer "In6.Cu")
		(net "DMI_CPU0_PCH_TX_DP<1>")
	)
	(arc
		(start 365.12373 -223.568006)
		(mid 365.201359 -223.289593)
		(end 365.406432 -223.085914)
		(width 0.0889)
		(layer "In6.Cu")
		(net "DMI_CPU0_PCH_TX_DP<1>")
	)
	(arc
		(start 361.656122 -226.336606)
		(mid 361.787036 -226.200246)
		(end 361.834684 -226.017328)
		(width 0.0889)
		(layer "In6.Cu")
		(net "DMI_CPU0_PCH_TX_DP<1>")
	)
	(arc
		(start 366.824768 -219.0115)
		(mid 366.955682 -218.87514)
		(end 367.00333 -218.692222)
		(width 0.0889)
		(layer "In6.Cu")
		(net "DMI_CPU0_PCH_TX_DP<1>")
	)
	(arc
		(start 366.06353 -220.319854)
		(mid 366.137521 -220.040288)
		(end 366.340136 -219.833952)
		(width 0.0889)
		(layer "In6.Cu")
		(net "DMI_CPU0_PCH_TX_DP<1>")
	)
	(arc
		(start 364.183676 -225.21799)
		(mid 364.183873 -225.210625)
		(end 364.18393 -225.203258)
		(width 0.0889)
		(layer "In6.Cu")
		(net "DMI_CPU0_PCH_TX_DP<1>")
	)
	(arc
		(start 368.225832 -214.947246)
		(mid 368.266645 -214.919943)
		(end 368.303556 -214.887556)
		(width 0.0889)
		(layer "In6.Cu")
		(net "DMI_CPU0_PCH_TX_DP<1>")
	)
	(arc
		(start 365.415322 -223.080834)
		(mid 365.546236 -222.944474)
		(end 365.593884 -222.761556)
		(width 0.0889)
		(layer "In6.Cu")
		(net "DMI_CPU0_PCH_TX_DP<1>")
	)
	(arc
		(start 361.185968 -227.150422)
		(mid 361.316882 -227.014062)
		(end 361.36453 -226.831144)
		(width 0.0889)
		(layer "In6.Cu")
		(net "DMI_CPU0_PCH_TX_DP<1>")
	)
	(arc
		(start 366.533684 -219.490544)
		(mid 366.613054 -219.21681)
		(end 366.815878 -219.01658)
		(width 0.0889)
		(layer "In6.Cu")
		(net "DMI_CPU0_PCH_TX_DP<1>")
	)
	(arc
		(start 367.286032 -217.554048)
		(mid 367.08096 -217.350369)
		(end 367.00333 -217.071956)
		(width 0.0889)
		(layer "In6.Cu")
		(net "DMI_CPU0_PCH_TX_DP<1>")
	)
	(arc
		(start 364.945168 -223.894904)
		(mid 365.076082 -223.758544)
		(end 365.12373 -223.575626)
		(width 0.0889)
		(layer "In6.Cu")
		(net "DMI_CPU0_PCH_TX_DP<1>")
	)
	(arc
		(start 364.005368 -225.522536)
		(mid 364.132622 -225.39257)
		(end 364.183676 -225.21799)
		(width 0.0889)
		(layer "In6.Cu")
		(net "DMI_CPU0_PCH_TX_DP<1>")
	)
	(arc
		(start 364.654084 -224.373948)
		(mid 364.733454 -224.100214)
		(end 364.936278 -223.899984)
		(width 0.0889)
		(layer "In6.Cu")
		(net "DMI_CPU0_PCH_TX_DP<1>")
	)
	(arc
		(start 366.355122 -221.453202)
		(mid 366.533719 -221.133924)
		(end 366.355122 -220.814646)
		(width 0.0889)
		(layer "In6.Cu")
		(net "DMI_CPU0_PCH_TX_DP<1>")
	)
	(arc
		(start 363.056678 -225.527616)
		(mid 363.330907 -225.451691)
		(end 363.60735 -225.51898)
		(width 0.0889)
		(layer "In6.Cu")
		(net "DMI_CPU0_PCH_TX_DP<1>")
	)
	(arc
		(start 363.622082 -225.527616)
		(mid 363.80928 -225.577759)
		(end 363.996478 -225.527616)
		(width 0.0889)
		(layer "In6.Cu")
		(net "DMI_CPU0_PCH_TX_DP<1>")
	)
	(arc
		(start 365.884968 -222.267018)
		(mid 366.015882 -222.130658)
		(end 366.06353 -221.94774)
		(width 0.0889)
		(layer "In6.Cu")
		(net "DMI_CPU0_PCH_TX_DP<1>")
	)
	(arc
		(start 365.593884 -222.746062)
		(mid 365.673254 -222.472328)
		(end 365.876078 -222.272098)
		(width 0.0889)
		(layer "In6.Cu")
		(net "DMI_CPU0_PCH_TX_DP<1>")
	)
	(arc
		(start 366.355122 -219.825316)
		(mid 366.486036 -219.688956)
		(end 366.533684 -219.506038)
		(width 0.0889)
		(layer "In6.Cu")
		(net "DMI_CPU0_PCH_TX_DP<1>")
	)
	(arc
		(start 366.346232 -220.809566)
		(mid 366.142751 -220.608762)
		(end 366.06353 -220.334078)
		(width 0.0889)
		(layer "In6.Cu")
		(net "DMI_CPU0_PCH_TX_DP<1>")
	)
	(arc
		(start 361.36453 -226.831144)
		(mid 361.436765 -226.55462)
		(end 361.63504 -226.348798)
		(width 0.0889)
		(layer "In6.Cu")
		(net "DMI_CPU0_PCH_TX_DP<1>")
	)
	(arc
		(start 367.294922 -218.197684)
		(mid 367.473519 -217.878406)
		(end 367.294922 -217.559128)
		(width 0.0889)
		(layer "In6.Cu")
		(net "DMI_CPU0_PCH_TX_DP<1>")
	)
	(arc
		(start 367.473484 -216.240614)
		(mid 367.551595 -215.963665)
		(end 367.755932 -215.761062)
		(width 0.0889)
		(layer "In6.Cu")
		(net "DMI_CPU0_PCH_TX_DP<1>")
	)
	(arc
		(start 367.294922 -216.569798)
		(mid 367.425836 -216.433438)
		(end 367.473484 -216.25052)
		(width 0.0889)
		(layer "In6.Cu")
		(net "DMI_CPU0_PCH_TX_DP<1>")
	)
	(arc
		(start 360.854498 -227.18014)
		(mid 361.018594 -227.204487)
		(end 361.177078 -227.155502)
		(width 0.0889)
		(layer "In6.Cu")
		(net "DMI_CPU0_PCH_TX_DP<1>")
	)
	(arc
		(start 362.116878 -225.527616)
		(mid 362.391107 -225.451691)
		(end 362.66755 -225.51898)
		(width 0.0889)
		(layer "In6.Cu")
		(net "DMI_CPU0_PCH_TX_DP<1>")
	)
	(segment
		(start 341.851996 -70.883526)
		(end 341.851996 -70.632066)
		(width 0.13208)
		(layer "F.Cu")
		(net "DMI_CPU0_PCH_TX_DP<0>")
	)
	(segment
		(start 360.050334 -228.99497)
		(end 360.05008 -228.994716)
		(width 0.13208)
		(layer "F.Cu")
		(net "DMI_CPU0_PCH_TX_DP<0>")
	)
	(segment
		(start 360.05008 -228.994716)
		(end 360.05008 -228.45903)
		(width 0.13208)
		(layer "F.Cu")
		(net "DMI_CPU0_PCH_TX_DP<0>")
	)
	(segment
		(start 341.851996 -70.632066)
		(end 341.52459 -70.30466)
		(width 0.13208)
		(layer "F.Cu")
		(net "DMI_CPU0_PCH_TX_DP<0>")
	)
	(segment
		(start 341.549736 -71.185786)
		(end 341.851996 -70.883526)
		(width 0.13208)
		(layer "F.Cu")
		(net "DMI_CPU0_PCH_TX_DP<0>")
	)
	(segment
		(start 367.956338 -213.529926)
		(end 367.857278 -213.430866)
		(width 0.0889)
		(layer "In6.Cu")
		(net "DMI_CPU0_PCH_TX_DP<0>")
	)
	(segment
		(start 366.353852 -218.198446)
		(end 366.35309 -218.198954)
		(width 0.0889)
		(layer "In6.Cu")
		(net "DMI_CPU0_PCH_TX_DP<0>")
	)
	(segment
		(start 366.35309 -218.198954)
		(end 366.355122 -218.197684)
		(width 0.0889)
		(layer "In6.Cu")
		(net "DMI_CPU0_PCH_TX_DP<0>")
	)
	(segment
		(start 385.883912 -177.735992)
		(end 380.830582 -149.081998)
		(width 0.14732)
		(layer "In6.Cu")
		(net "DMI_CPU0_PCH_TX_DP<0>")
	)
	(segment
		(start 341.844376 -71.480426)
		(end 341.549736 -71.185786)
		(width 0.14732)
		(layer "In6.Cu")
		(net "DMI_CPU0_PCH_TX_DP<0>")
	)
	(segment
		(start 362.774484 -224.389442)
		(end 362.774484 -224.379536)
		(width 0.0889)
		(layer "In6.Cu")
		(net "DMI_CPU0_PCH_TX_DP<0>")
	)
	(segment
		(start 359.955084 -227.667058)
		(end 359.955084 -227.635054)
		(width 0.0889)
		(layer "In6.Cu")
		(net "DMI_CPU0_PCH_TX_DP<0>")
	)
	(segment
		(start 363.056932 -223.899984)
		(end 363.065822 -223.894904)
		(width 0.0889)
		(layer "In6.Cu")
		(net "DMI_CPU0_PCH_TX_DP<0>")
	)
	(segment
		(start 364.466632 -223.085914)
		(end 364.475522 -223.080834)
		(width 0.0889)
		(layer "In6.Cu")
		(net "DMI_CPU0_PCH_TX_DP<0>")
	)
	(segment
		(start 360.246168 -228.139752)
		(end 360.238294 -228.13518)
		(width 0.0889)
		(layer "In6.Cu")
		(net "DMI_CPU0_PCH_TX_DP<0>")
	)
	(segment
		(start 361.732322 -223.893888)
		(end 361.742736 -223.899984)
		(width 0.0889)
		(layer "In6.Cu")
		(net "DMI_CPU0_PCH_TX_DP<0>")
	)
	(segment
		(start 367.956338 -212.803486)
		(end 367.857278 -212.704426)
		(width 0.0889)
		(layer "In6.Cu")
		(net "DMI_CPU0_PCH_TX_DP<0>")
	)
	(segment
		(start 383.946908 -188.722254)
		(end 385.883912 -177.735992)
		(width 0.14732)
		(layer "In6.Cu")
		(net "DMI_CPU0_PCH_TX_DP<0>")
	)
	(segment
		(start 367.956338 -211.614766)
		(end 367.956338 -211.345272)
		(width 0.0889)
		(layer "In6.Cu")
		(net "DMI_CPU0_PCH_TX_DP<0>")
	)
	(segment
		(start 360.708448 -226.340924)
		(end 360.716322 -226.336352)
		(width 0.0889)
		(layer "In6.Cu")
		(net "DMI_CPU0_PCH_TX_DP<0>")
	)
	(segment
		(start 367.857278 -212.704426)
		(end 367.857278 -212.440266)
		(width 0.0889)
		(layer "In6.Cu")
		(net "DMI_CPU0_PCH_TX_DP<0>")
	)
	(segment
		(start 368.293904 -207.10906)
		(end 373.751856 -199.314816)
		(width 0.14732)
		(layer "In6.Cu")
		(net "DMI_CPU0_PCH_TX_DP<0>")
	)
	(segment
		(start 367.914174 -211.28101)
		(end 367.914174 -209.266282)
		(width 0.14732)
		(layer "In6.Cu")
		(net "DMI_CPU0_PCH_TX_DP<0>")
	)
	(segment
		(start 380.830582 -149.081998)
		(end 348.663768 -88.507062)
		(width 0.14732)
		(layer "In6.Cu")
		(net "DMI_CPU0_PCH_TX_DP<0>")
	)
	(segment
		(start 365.407194 -220.810074)
		(end 365.406432 -220.809566)
		(width 0.0889)
		(layer "In6.Cu")
		(net "DMI_CPU0_PCH_TX_DP<0>")
	)
	(segment
		(start 361.178094 -224.879408)
		(end 361.177078 -224.8789)
		(width 0.0889)
		(layer "In6.Cu")
		(net "DMI_CPU0_PCH_TX_DP<0>")
	)
	(segment
		(start 367.857278 -213.430866)
		(end 367.857278 -213.166706)
		(width 0.0889)
		(layer "In6.Cu")
		(net "DMI_CPU0_PCH_TX_DP<0>")
	)
	(segment
		(start 366.533684 -216.25052)
		(end 366.533684 -216.235026)
		(width 0.0889)
		(layer "In6.Cu")
		(net "DMI_CPU0_PCH_TX_DP<0>")
	)
	(segment
		(start 360.701336 -226.345242)
		(end 360.706162 -226.342448)
		(width 0.0889)
		(layer "In6.Cu")
		(net "DMI_CPU0_PCH_TX_DP<0>")
	)
	(segment
		(start 365.593884 -219.506038)
		(end 365.593884 -219.490544)
		(width 0.0889)
		(layer "In6.Cu")
		(net "DMI_CPU0_PCH_TX_DP<0>")
	)
	(segment
		(start 362.588556 -224.713038)
		(end 362.595922 -224.70872)
		(width 0.0889)
		(layer "In6.Cu")
		(net "DMI_CPU0_PCH_TX_DP<0>")
	)
	(segment
		(start 367.956338 -212.077046)
		(end 367.857278 -211.977986)
		(width 0.0889)
		(layer "In6.Cu")
		(net "DMI_CPU0_PCH_TX_DP<0>")
	)
	(segment
		(start 365.12373 -220.327474)
		(end 365.12373 -220.319854)
		(width 0.0889)
		(layer "In6.Cu")
		(net "DMI_CPU0_PCH_TX_DP<0>")
	)
	(segment
		(start 367.956338 -211.345272)
		(end 367.914174 -211.303108)
		(width 0.0889)
		(layer "In6.Cu")
		(net "DMI_CPU0_PCH_TX_DP<0>")
	)
	(segment
		(start 360.362754 -228.45903)
		(end 360.420158 -228.401626)
		(width 0.0889)
		(layer "In6.Cu")
		(net "DMI_CPU0_PCH_TX_DP<0>")
	)
	(segment
		(start 379.840998 -194.585844)
		(end 383.946908 -188.722254)
		(width 0.14732)
		(layer "In6.Cu")
		(net "DMI_CPU0_PCH_TX_DP<0>")
	)
	(segment
		(start 373.751856 -199.314816)
		(end 378.288804 -196.138038)
		(width 0.14732)
		(layer "In6.Cu")
		(net "DMI_CPU0_PCH_TX_DP<0>")
	)
	(segment
		(start 365.403638 -221.459806)
		(end 365.406432 -221.458282)
		(width 0.0889)
		(layer "In6.Cu")
		(net "DMI_CPU0_PCH_TX_DP<0>")
	)
	(segment
		(start 367.00333 -215.436704)
		(end 367.00333 -215.42121)
		(width 0.0889)
		(layer "In6.Cu")
		(net "DMI_CPU0_PCH_TX_DP<0>")
	)
	(segment
		(start 348.663768 -88.507062)
		(end 342.927178 -75.372468)
		(width 0.14732)
		(layer "In6.Cu")
		(net "DMI_CPU0_PCH_TX_DP<0>")
	)
	(segment
		(start 367.914174 -211.303108)
		(end 367.914174 -211.28101)
		(width 0.0889)
		(layer "In6.Cu")
		(net "DMI_CPU0_PCH_TX_DP<0>")
	)
	(segment
		(start 360.05008 -228.45903)
		(end 360.362754 -228.45903)
		(width 0.0889)
		(layer "In6.Cu")
		(net "DMI_CPU0_PCH_TX_DP<0>")
	)
	(segment
		(start 367.857278 -212.440266)
		(end 367.956338 -212.341206)
		(width 0.0889)
		(layer "In6.Cu")
		(net "DMI_CPU0_PCH_TX_DP<0>")
	)
	(segment
		(start 366.340136 -216.578434)
		(end 366.344962 -216.57564)
		(width 0.0889)
		(layer "In6.Cu")
		(net "DMI_CPU0_PCH_TX_DP<0>")
	)
	(segment
		(start 365.406432 -219.830396)
		(end 365.415322 -219.825316)
		(width 0.0889)
		(layer "In6.Cu")
		(net "DMI_CPU0_PCH_TX_DP<0>")
	)
	(segment
		(start 342.927178 -75.372468)
		(end 341.844376 -72.49795)
		(width 0.14732)
		(layer "In6.Cu")
		(net "DMI_CPU0_PCH_TX_DP<0>")
	)
	(segment
		(start 360.894884 -226.017328)
		(end 360.894884 -225.99523)
		(width 0.0889)
		(layer "In6.Cu")
		(net "DMI_CPU0_PCH_TX_DP<0>")
	)
	(segment
		(start 360.42473 -226.83978)
		(end 360.42473 -226.831144)
		(width 0.0889)
		(layer "In6.Cu")
		(net "DMI_CPU0_PCH_TX_DP<0>")
	)
	(segment
		(start 362.587032 -224.7138)
		(end 362.588556 -224.713038)
		(width 0.0889)
		(layer "In6.Cu")
		(net "DMI_CPU0_PCH_TX_DP<0>")
	)
	(segment
		(start 341.844376 -72.49795)
		(end 341.844376 -71.480426)
		(width 0.14732)
		(layer "In6.Cu")
		(net "DMI_CPU0_PCH_TX_DP<0>")
	)
	(segment
		(start 378.288804 -196.138038)
		(end 379.840998 -194.585844)
		(width 0.14732)
		(layer "In6.Cu")
		(net "DMI_CPU0_PCH_TX_DP<0>")
	)
	(segment
		(start 366.815878 -215.761062)
		(end 366.824768 -215.755982)
		(width 0.0889)
		(layer "In6.Cu")
		(net "DMI_CPU0_PCH_TX_DP<0>")
	)
	(segment
		(start 361.185968 -224.88398)
		(end 361.178094 -224.879408)
		(width 0.0889)
		(layer "In6.Cu")
		(net "DMI_CPU0_PCH_TX_DP<0>")
	)
	(segment
		(start 366.347248 -216.574116)
		(end 366.355122 -216.569544)
		(width 0.0889)
		(layer "In6.Cu")
		(net "DMI_CPU0_PCH_TX_DP<0>")
	)
	(segment
		(start 366.344962 -216.57564)
		(end 366.347248 -216.574116)
		(width 0.0889)
		(layer "In6.Cu")
		(net "DMI_CPU0_PCH_TX_DP<0>")
	)
	(segment
		(start 362.203746 -224.70872)
		(end 362.212636 -224.7138)
		(width 0.0889)
		(layer "In6.Cu")
		(net "DMI_CPU0_PCH_TX_DP<0>")
	)
	(segment
		(start 367.857278 -211.713826)
		(end 367.956338 -211.614766)
		(width 0.0889)
		(layer "In6.Cu")
		(net "DMI_CPU0_PCH_TX_DP<0>")
	)
	(segment
		(start 367.956338 -213.067646)
		(end 367.956338 -212.803486)
		(width 0.0889)
		(layer "In6.Cu")
		(net "DMI_CPU0_PCH_TX_DP<0>")
	)
	(segment
		(start 364.936278 -222.272098)
		(end 364.945168 -222.267018)
		(width 0.0889)
		(layer "In6.Cu")
		(net "DMI_CPU0_PCH_TX_DP<0>")
	)
	(segment
		(start 367.362994 -214.88781)
		(end 367.956338 -214.294466)
		(width 0.0889)
		(layer "In6.Cu")
		(net "DMI_CPU0_PCH_TX_DP<0>")
	)
	(segment
		(start 367.956338 -214.294466)
		(end 367.956338 -213.529926)
		(width 0.0889)
		(layer "In6.Cu")
		(net "DMI_CPU0_PCH_TX_DP<0>")
	)
	(segment
		(start 367.857278 -211.977986)
		(end 367.857278 -211.713826)
		(width 0.0889)
		(layer "In6.Cu")
		(net "DMI_CPU0_PCH_TX_DP<0>")
	)
	(segment
		(start 361.177078 -225.527616)
		(end 361.185968 -225.522536)
		(width 0.0889)
		(layer "In6.Cu")
		(net "DMI_CPU0_PCH_TX_DP<0>")
	)
	(segment
		(start 360.716322 -226.336352)
		(end 360.716322 -226.336606)
		(width 0.0889)
		(layer "In6.Cu")
		(net "DMI_CPU0_PCH_TX_DP<0>")
	)
	(segment
		(start 365.39424 -219.837508)
		(end 365.406432 -219.830396)
		(width 0.0889)
		(layer "In6.Cu")
		(net "DMI_CPU0_PCH_TX_DP<0>")
	)
	(segment
		(start 360.238294 -228.13518)
		(end 360.237278 -228.134672)
		(width 0.0889)
		(layer "In6.Cu")
		(net "DMI_CPU0_PCH_TX_DP<0>")
	)
	(segment
		(start 365.876078 -219.01658)
		(end 365.884968 -219.0115)
		(width 0.0889)
		(layer "In6.Cu")
		(net "DMI_CPU0_PCH_TX_DP<0>")
	)
	(segment
		(start 364.654084 -222.761556)
		(end 364.654084 -222.746062)
		(width 0.0889)
		(layer "In6.Cu")
		(net "DMI_CPU0_PCH_TX_DP<0>")
	)
	(segment
		(start 366.340136 -218.20632)
		(end 366.353852 -218.198446)
		(width 0.0889)
		(layer "In6.Cu")
		(net "DMI_CPU0_PCH_TX_DP<0>")
	)
	(segment
		(start 365.406432 -221.458282)
		(end 365.407956 -221.45752)
		(width 0.0889)
		(layer "In6.Cu")
		(net "DMI_CPU0_PCH_TX_DP<0>")
	)
	(segment
		(start 360.706162 -226.342448)
		(end 360.708448 -226.340924)
		(width 0.0889)
		(layer "In6.Cu")
		(net "DMI_CPU0_PCH_TX_DP<0>")
	)
	(segment
		(start 362.025184 -224.379536)
		(end 362.025184 -224.389442)
		(width 0.0889)
		(layer "In6.Cu")
		(net "DMI_CPU0_PCH_TX_DP<0>")
	)
	(segment
		(start 360.894884 -224.404936)
		(end 360.894884 -224.373948)
		(width 0.0889)
		(layer "In6.Cu")
		(net "DMI_CPU0_PCH_TX_DP<0>")
	)
	(segment
		(start 366.355122 -216.569544)
		(end 366.355122 -216.569798)
		(width 0.0889)
		(layer "In6.Cu")
		(net "DMI_CPU0_PCH_TX_DP<0>")
	)
	(segment
		(start 367.857278 -213.166706)
		(end 367.956338 -213.067646)
		(width 0.0889)
		(layer "In6.Cu")
		(net "DMI_CPU0_PCH_TX_DP<0>")
	)
	(segment
		(start 365.407956 -221.45752)
		(end 365.415322 -221.453202)
		(width 0.0889)
		(layer "In6.Cu")
		(net "DMI_CPU0_PCH_TX_DP<0>")
	)
	(segment
		(start 367.956338 -212.341206)
		(end 367.956338 -212.077046)
		(width 0.0889)
		(layer "In6.Cu")
		(net "DMI_CPU0_PCH_TX_DP<0>")
	)
	(segment
		(start 367.914174 -209.266282)
		(end 368.293904 -207.10906)
		(width 0.14732)
		(layer "In6.Cu")
		(net "DMI_CPU0_PCH_TX_DP<0>")
	)
	(segment
		(start 366.355122 -217.559128)
		(end 366.346232 -217.554048)
		(width 0.0889)
		(layer "In6.Cu")
		(net "DMI_CPU0_PCH_TX_DP<0>")
	)
	(segment
		(start 366.06353 -217.07856)
		(end 366.06353 -217.064336)
		(width 0.0889)
		(layer "In6.Cu")
		(net "DMI_CPU0_PCH_TX_DP<0>")
	)
	(segment
		(start 365.400336 -221.461838)
		(end 365.403638 -221.459806)
		(width 0.0889)
		(layer "In6.Cu")
		(net "DMI_CPU0_PCH_TX_DP<0>")
	)
	(segment
		(start 363.244384 -223.575626)
		(end 363.244384 -223.557084)
		(width 0.0889)
		(layer "In6.Cu")
		(net "DMI_CPU0_PCH_TX_DP<0>")
	)
	(segment
		(start 365.415322 -220.814646)
		(end 365.407194 -220.810074)
		(width 0.0889)
		(layer "In6.Cu")
		(net "DMI_CPU0_PCH_TX_DP<0>")
	)
	(arc
		(start 362.595922 -224.70872)
		(mid 362.726836 -224.57236)
		(end 362.774484 -224.389442)
		(width 0.0889)
		(layer "In6.Cu")
		(net "DMI_CPU0_PCH_TX_DP<0>")
	)
	(arc
		(start 363.244384 -223.557084)
		(mid 363.324546 -223.284895)
		(end 363.526832 -223.085914)
		(width 0.0889)
		(layer "In6.Cu")
		(net "DMI_CPU0_PCH_TX_DP<0>")
	)
	(arc
		(start 361.177078 -224.8789)
		(mid 360.974255 -224.678669)
		(end 360.894884 -224.404936)
		(width 0.0889)
		(layer "In6.Cu")
		(net "DMI_CPU0_PCH_TX_DP<0>")
	)
	(arc
		(start 366.06353 -218.692222)
		(mid 366.137521 -218.412656)
		(end 366.340136 -218.20632)
		(width 0.0889)
		(layer "In6.Cu")
		(net "DMI_CPU0_PCH_TX_DP<0>")
	)
	(arc
		(start 362.212636 -224.7138)
		(mid 362.399834 -224.763943)
		(end 362.587032 -224.7138)
		(width 0.0889)
		(layer "In6.Cu")
		(net "DMI_CPU0_PCH_TX_DP<0>")
	)
	(arc
		(start 360.237532 -227.155502)
		(mid 360.372465 -227.022148)
		(end 360.42473 -226.83978)
		(width 0.0889)
		(layer "In6.Cu")
		(net "DMI_CPU0_PCH_TX_DP<0>")
	)
	(arc
		(start 365.415322 -221.453202)
		(mid 365.593919 -221.133924)
		(end 365.415322 -220.814646)
		(width 0.0889)
		(layer "In6.Cu")
		(net "DMI_CPU0_PCH_TX_DP<0>")
	)
	(arc
		(start 361.177078 -223.899984)
		(mid 361.453891 -223.824114)
		(end 361.732322 -223.893888)
		(width 0.0889)
		(layer "In6.Cu")
		(net "DMI_CPU0_PCH_TX_DP<0>")
	)
	(arc
		(start 362.025184 -224.389442)
		(mid 362.072863 -224.572342)
		(end 362.203746 -224.70872)
		(width 0.0889)
		(layer "In6.Cu")
		(net "DMI_CPU0_PCH_TX_DP<0>")
	)
	(arc
		(start 366.346232 -217.554048)
		(mid 366.142751 -217.353244)
		(end 366.06353 -217.07856)
		(width 0.0889)
		(layer "In6.Cu")
		(net "DMI_CPU0_PCH_TX_DP<0>")
	)
	(arc
		(start 366.06353 -217.064336)
		(mid 366.137521 -216.78477)
		(end 366.340136 -216.578434)
		(width 0.0889)
		(layer "In6.Cu")
		(net "DMI_CPU0_PCH_TX_DP<0>")
	)
	(arc
		(start 363.065822 -223.894904)
		(mid 363.196736 -223.758544)
		(end 363.244384 -223.575626)
		(width 0.0889)
		(layer "In6.Cu")
		(net "DMI_CPU0_PCH_TX_DP<0>")
	)
	(arc
		(start 367.285524 -214.947246)
		(mid 367.326194 -214.920052)
		(end 367.362994 -214.88781)
		(width 0.0889)
		(layer "In6.Cu")
		(net "DMI_CPU0_PCH_TX_DP<0>")
	)
	(arc
		(start 366.533684 -216.235026)
		(mid 366.613054 -215.961292)
		(end 366.815878 -215.761062)
		(width 0.0889)
		(layer "In6.Cu")
		(net "DMI_CPU0_PCH_TX_DP<0>")
	)
	(arc
		(start 365.884968 -219.0115)
		(mid 366.015882 -218.87514)
		(end 366.06353 -218.692222)
		(width 0.0889)
		(layer "In6.Cu")
		(net "DMI_CPU0_PCH_TX_DP<0>")
	)
	(arc
		(start 364.945168 -222.267018)
		(mid 365.076082 -222.130658)
		(end 365.12373 -221.94774)
		(width 0.0889)
		(layer "In6.Cu")
		(net "DMI_CPU0_PCH_TX_DP<0>")
	)
	(arc
		(start 360.894884 -225.99523)
		(mid 360.975795 -225.725102)
		(end 361.177078 -225.527616)
		(width 0.0889)
		(layer "In6.Cu")
		(net "DMI_CPU0_PCH_TX_DP<0>")
	)
	(arc
		(start 366.355122 -216.569798)
		(mid 366.486036 -216.433438)
		(end 366.533684 -216.25052)
		(width 0.0889)
		(layer "In6.Cu")
		(net "DMI_CPU0_PCH_TX_DP<0>")
	)
	(arc
		(start 363.526832 -223.085914)
		(mid 363.809534 -223.010172)
		(end 364.092236 -223.085914)
		(width 0.0889)
		(layer "In6.Cu")
		(net "DMI_CPU0_PCH_TX_DP<0>")
	)
	(arc
		(start 364.092236 -223.085914)
		(mid 364.279434 -223.136057)
		(end 364.466632 -223.085914)
		(width 0.0889)
		(layer "In6.Cu")
		(net "DMI_CPU0_PCH_TX_DP<0>")
	)
	(arc
		(start 365.406432 -220.809566)
		(mid 365.20136 -220.605887)
		(end 365.12373 -220.327474)
		(width 0.0889)
		(layer "In6.Cu")
		(net "DMI_CPU0_PCH_TX_DP<0>")
	)
	(arc
		(start 359.955084 -227.635054)
		(mid 360.033195 -227.358105)
		(end 360.237532 -227.155502)
		(width 0.0889)
		(layer "In6.Cu")
		(net "DMI_CPU0_PCH_TX_DP<0>")
	)
	(arc
		(start 366.824768 -215.755982)
		(mid 366.955682 -215.619622)
		(end 367.00333 -215.436704)
		(width 0.0889)
		(layer "In6.Cu")
		(net "DMI_CPU0_PCH_TX_DP<0>")
	)
	(arc
		(start 364.475522 -223.080834)
		(mid 364.606436 -222.944474)
		(end 364.654084 -222.761556)
		(width 0.0889)
		(layer "In6.Cu")
		(net "DMI_CPU0_PCH_TX_DP<0>")
	)
	(arc
		(start 364.654084 -222.746062)
		(mid 364.733454 -222.472328)
		(end 364.936278 -222.272098)
		(width 0.0889)
		(layer "In6.Cu")
		(net "DMI_CPU0_PCH_TX_DP<0>")
	)
	(arc
		(start 360.894884 -224.373948)
		(mid 360.974254 -224.100214)
		(end 361.177078 -223.899984)
		(width 0.0889)
		(layer "In6.Cu")
		(net "DMI_CPU0_PCH_TX_DP<0>")
	)
	(arc
		(start 361.36453 -225.203258)
		(mid 361.316851 -225.020358)
		(end 361.185968 -224.88398)
		(width 0.0889)
		(layer "In6.Cu")
		(net "DMI_CPU0_PCH_TX_DP<0>")
	)
	(arc
		(start 365.12373 -221.94774)
		(mid 365.197721 -221.668174)
		(end 365.400336 -221.461838)
		(width 0.0889)
		(layer "In6.Cu")
		(net "DMI_CPU0_PCH_TX_DP<0>")
	)
	(arc
		(start 365.593884 -219.490544)
		(mid 365.673254 -219.21681)
		(end 365.876078 -219.01658)
		(width 0.0889)
		(layer "In6.Cu")
		(net "DMI_CPU0_PCH_TX_DP<0>")
	)
	(arc
		(start 360.237278 -228.134672)
		(mid 360.035996 -227.937185)
		(end 359.955084 -227.667058)
		(width 0.0889)
		(layer "In6.Cu")
		(net "DMI_CPU0_PCH_TX_DP<0>")
	)
	(arc
		(start 366.355122 -218.197684)
		(mid 366.533719 -217.878406)
		(end 366.355122 -217.559128)
		(width 0.0889)
		(layer "In6.Cu")
		(net "DMI_CPU0_PCH_TX_DP<0>")
	)
	(arc
		(start 365.415322 -219.825316)
		(mid 365.546236 -219.688956)
		(end 365.593884 -219.506038)
		(width 0.0889)
		(layer "In6.Cu")
		(net "DMI_CPU0_PCH_TX_DP<0>")
	)
	(arc
		(start 360.420158 -228.401626)
		(mid 360.362002 -228.251513)
		(end 360.246168 -228.139752)
		(width 0.0889)
		(layer "In6.Cu")
		(net "DMI_CPU0_PCH_TX_DP<0>")
	)
	(arc
		(start 362.774484 -224.379536)
		(mid 362.852595 -224.102587)
		(end 363.056932 -223.899984)
		(width 0.0889)
		(layer "In6.Cu")
		(net "DMI_CPU0_PCH_TX_DP<0>")
	)
	(arc
		(start 365.12373 -220.319854)
		(mid 365.195965 -220.04333)
		(end 365.39424 -219.837508)
		(width 0.0889)
		(layer "In6.Cu")
		(net "DMI_CPU0_PCH_TX_DP<0>")
	)
	(arc
		(start 360.716322 -226.336606)
		(mid 360.847236 -226.200246)
		(end 360.894884 -226.017328)
		(width 0.0889)
		(layer "In6.Cu")
		(net "DMI_CPU0_PCH_TX_DP<0>")
	)
	(arc
		(start 367.00333 -215.42121)
		(mid 367.0827 -215.147476)
		(end 367.285524 -214.947246)
		(width 0.0889)
		(layer "In6.Cu")
		(net "DMI_CPU0_PCH_TX_DP<0>")
	)
	(arc
		(start 360.42473 -226.831144)
		(mid 360.498721 -226.551578)
		(end 360.701336 -226.345242)
		(width 0.0889)
		(layer "In6.Cu")
		(net "DMI_CPU0_PCH_TX_DP<0>")
	)
	(arc
		(start 361.364276 -225.21799)
		(mid 361.364473 -225.210625)
		(end 361.36453 -225.203258)
		(width 0.0889)
		(layer "In6.Cu")
		(net "DMI_CPU0_PCH_TX_DP<0>")
	)
	(arc
		(start 361.185968 -225.522536)
		(mid 361.313222 -225.39257)
		(end 361.364276 -225.21799)
		(width 0.0889)
		(layer "In6.Cu")
		(net "DMI_CPU0_PCH_TX_DP<0>")
	)
	(arc
		(start 361.742736 -223.899984)
		(mid 361.947071 -224.102589)
		(end 362.025184 -224.379536)
		(width 0.0889)
		(layer "In6.Cu")
		(net "DMI_CPU0_PCH_TX_DP<0>")
	)
	(segment
		(start 351.285556 -60.919614)
		(end 351.90176 -60.919614)
		(width 0.13208)
		(layer "F.Cu")
		(net "DMI_CPU0_PCH_TX_DN<7>")
	)
	(segment
		(start 351.90176 -60.919614)
		(end 352.20402 -60.617354)
		(width 0.13208)
		(layer "F.Cu")
		(net "DMI_CPU0_PCH_TX_DN<7>")
	)
	(segment
		(start 366.159034 -228.180646)
		(end 366.159034 -227.64496)
		(width 0.13208)
		(layer "F.Cu")
		(net "DMI_CPU0_PCH_TX_DN<7>")
	)
	(segment
		(start 350.957896 -60.591954)
		(end 351.285556 -60.919614)
		(width 0.13208)
		(layer "F.Cu")
		(net "DMI_CPU0_PCH_TX_DN<7>")
	)
	(segment
		(start 366.15878 -228.1809)
		(end 366.159034 -228.180646)
		(width 0.13208)
		(layer "F.Cu")
		(net "DMI_CPU0_PCH_TX_DN<7>")
	)
	(segment
		(start 352.49866 -60.911994)
		(end 352.20402 -60.617354)
		(width 0.14732)
		(layer "In6.Cu")
		(net "DMI_CPU0_PCH_TX_DN<7>")
	)
	(segment
		(start 369.07343 -221.963234)
		(end 369.07343 -221.94774)
		(width 0.0889)
		(layer "In6.Cu")
		(net "DMI_CPU0_PCH_TX_DN<7>")
	)
	(segment
		(start 352.817684 -60.911994)
		(end 352.49866 -60.911994)
		(width 0.14732)
		(layer "In6.Cu")
		(net "DMI_CPU0_PCH_TX_DN<7>")
	)
	(segment
		(start 352.57613 -81.955132)
		(end 350.106742 -73.91146)
		(width 0.14732)
		(layer "In6.Cu")
		(net "DMI_CPU0_PCH_TX_DN<7>")
	)
	(segment
		(start 353.119182 -61.213492)
		(end 352.817684 -60.911994)
		(width 0.14732)
		(layer "In6.Cu")
		(net "DMI_CPU0_PCH_TX_DN<7>")
	)
	(segment
		(start 383.372106 -196.327522)
		(end 386.26542 -192.195196)
		(width 0.14732)
		(layer "In6.Cu")
		(net "DMI_CPU0_PCH_TX_DN<7>")
	)
	(segment
		(start 388.08152 -190.586614)
		(end 390.090152 -179.197762)
		(width 0.14732)
		(layer "In6.Cu")
		(net "DMI_CPU0_PCH_TX_DN<7>")
	)
	(segment
		(start 371.935248 -211.47151)
		(end 371.935248 -209.619088)
		(width 0.14732)
		(layer "In6.Cu")
		(net "DMI_CPU0_PCH_TX_DN<7>")
	)
	(segment
		(start 387.846316 -190.922656)
		(end 387.846316 -190.922402)
		(width 0.14732)
		(layer "In6.Cu")
		(net "DMI_CPU0_PCH_TX_DN<7>")
	)
	(segment
		(start 380.476506 -199.223122)
		(end 383.372106 -196.327522)
		(width 0.14732)
		(layer "In6.Cu")
		(net "DMI_CPU0_PCH_TX_DN<7>")
	)
	(segment
		(start 368.603784 -222.77578)
		(end 368.603784 -222.761556)
		(width 0.0889)
		(layer "In6.Cu")
		(net "DMI_CPU0_PCH_TX_DN<7>")
	)
	(segment
		(start 369.543584 -219.515944)
		(end 369.543584 -219.506038)
		(width 0.0889)
		(layer "In6.Cu")
		(net "DMI_CPU0_PCH_TX_DN<7>")
	)
	(segment
		(start 369.261136 -220.644212)
		(end 369.252246 -220.639132)
		(width 0.0889)
		(layer "In6.Cu")
		(net "DMI_CPU0_PCH_TX_DN<7>")
	)
	(segment
		(start 370.204238 -216.737946)
		(end 370.206778 -216.736422)
		(width 0.0889)
		(layer "In6.Cu")
		(net "DMI_CPU0_PCH_TX_DN<7>")
	)
	(segment
		(start 366.159034 -227.64496)
		(end 366.315498 -227.373942)
		(width 0.0889)
		(layer "In6.Cu")
		(net "DMI_CPU0_PCH_TX_DN<7>")
	)
	(segment
		(start 367.380774 -226.507294)
		(end 367.381536 -226.506786)
		(width 0.0889)
		(layer "In6.Cu")
		(net "DMI_CPU0_PCH_TX_DN<7>")
	)
	(segment
		(start 347.730826 -65.811908)
		(end 349.186246 -64.356488)
		(width 0.14732)
		(layer "In6.Cu")
		(net "DMI_CPU0_PCH_TX_DN<7>")
	)
	(segment
		(start 369.251992 -221.628462)
		(end 369.267232 -221.619572)
		(width 0.0889)
		(layer "In6.Cu")
		(net "DMI_CPU0_PCH_TX_DN<7>")
	)
	(segment
		(start 367.851436 -224.7138)
		(end 367.842546 -224.70872)
		(width 0.0889)
		(layer "In6.Cu")
		(net "DMI_CPU0_PCH_TX_DN<7>")
	)
	(segment
		(start 371.935248 -211.493608)
		(end 371.935248 -211.47151)
		(width 0.0889)
		(layer "In6.Cu")
		(net "DMI_CPU0_PCH_TX_DN<7>")
	)
	(segment
		(start 349.179896 -69.838824)
		(end 347.730826 -68.389754)
		(width 0.14732)
		(layer "In6.Cu")
		(net "DMI_CPU0_PCH_TX_DN<7>")
	)
	(segment
		(start 368.133884 -223.585532)
		(end 368.133884 -223.56699)
		(width 0.0889)
		(layer "In6.Cu")
		(net "DMI_CPU0_PCH_TX_DN<7>")
	)
	(segment
		(start 350.106742 -72.076564)
		(end 349.179896 -69.838824)
		(width 0.14732)
		(layer "In6.Cu")
		(net "DMI_CPU0_PCH_TX_DN<7>")
	)
	(segment
		(start 371.256814 -215.02243)
		(end 371.893338 -214.385906)
		(width 0.0889)
		(layer "In6.Cu")
		(net "DMI_CPU0_PCH_TX_DN<7>")
	)
	(segment
		(start 369.267232 -221.619572)
		(end 369.266978 -221.619826)
		(width 0.0889)
		(layer "In6.Cu")
		(net "DMI_CPU0_PCH_TX_DN<7>")
	)
	(segment
		(start 370.200682 -218.367864)
		(end 370.201444 -218.367356)
		(width 0.0889)
		(layer "In6.Cu")
		(net "DMI_CPU0_PCH_TX_DN<7>")
	)
	(segment
		(start 370.01323 -218.707716)
		(end 370.01323 -218.692222)
		(width 0.0889)
		(layer "In6.Cu")
		(net "DMI_CPU0_PCH_TX_DN<7>")
	)
	(segment
		(start 371.131592 -215.117426)
		(end 371.13972 -215.112092)
		(width 0.0889)
		(layer "In6.Cu")
		(net "DMI_CPU0_PCH_TX_DN<7>")
	)
	(segment
		(start 368.782346 -222.442278)
		(end 368.791236 -222.437198)
		(width 0.0889)
		(layer "In6.Cu")
		(net "DMI_CPU0_PCH_TX_DN<7>")
	)
	(segment
		(start 367.85042 -225.693478)
		(end 367.851436 -225.69297)
		(width 0.0889)
		(layer "In6.Cu")
		(net "DMI_CPU0_PCH_TX_DN<7>")
	)
	(segment
		(start 384.450844 -147.215606)
		(end 352.57613 -81.955132)
		(width 0.14732)
		(layer "In6.Cu")
		(net "DMI_CPU0_PCH_TX_DN<7>")
	)
	(segment
		(start 371.893338 -214.385906)
		(end 371.893338 -211.535518)
		(width 0.0889)
		(layer "In6.Cu")
		(net "DMI_CPU0_PCH_TX_DN<7>")
	)
	(segment
		(start 349.186246 -64.356488)
		(end 350.98736 -64.356488)
		(width 0.14732)
		(layer "In6.Cu")
		(net "DMI_CPU0_PCH_TX_DN<7>")
	)
	(segment
		(start 350.98736 -64.356488)
		(end 353.119182 -62.224666)
		(width 0.14732)
		(layer "In6.Cu")
		(net "DMI_CPU0_PCH_TX_DN<7>")
	)
	(segment
		(start 370.199158 -218.368626)
		(end 370.200682 -218.367864)
		(width 0.0889)
		(layer "In6.Cu")
		(net "DMI_CPU0_PCH_TX_DN<7>")
	)
	(segment
		(start 387.846316 -190.922402)
		(end 388.08152 -190.586614)
		(width 0.14732)
		(layer "In6.Cu")
		(net "DMI_CPU0_PCH_TX_DN<7>")
	)
	(segment
		(start 353.119182 -62.224666)
		(end 353.119182 -61.213492)
		(width 0.14732)
		(layer "In6.Cu")
		(net "DMI_CPU0_PCH_TX_DN<7>")
	)
	(segment
		(start 367.842546 -224.070164)
		(end 367.851436 -224.065084)
		(width 0.0889)
		(layer "In6.Cu")
		(net "DMI_CPU0_PCH_TX_DN<7>")
	)
	(segment
		(start 350.106742 -73.91146)
		(end 350.106742 -72.076564)
		(width 0.14732)
		(layer "In6.Cu")
		(net "DMI_CPU0_PCH_TX_DN<7>")
	)
	(segment
		(start 386.26542 -192.195196)
		(end 387.618224 -191.24803)
		(width 0.14732)
		(layer "In6.Cu")
		(net "DMI_CPU0_PCH_TX_DN<7>")
	)
	(segment
		(start 367.372646 -226.511866)
		(end 367.380774 -226.507294)
		(width 0.0889)
		(layer "In6.Cu")
		(net "DMI_CPU0_PCH_TX_DN<7>")
	)
	(segment
		(start 366.315498 -227.373942)
		(end 366.404398 -227.35032)
		(width 0.0889)
		(layer "In6.Cu")
		(net "DMI_CPU0_PCH_TX_DN<7>")
	)
	(segment
		(start 370.201444 -216.73947)
		(end 370.204238 -216.737946)
		(width 0.0889)
		(layer "In6.Cu")
		(net "DMI_CPU0_PCH_TX_DN<7>")
	)
	(segment
		(start 390.090152 -179.197762)
		(end 384.450844 -147.215606)
		(width 0.14732)
		(layer "In6.Cu")
		(net "DMI_CPU0_PCH_TX_DN<7>")
	)
	(segment
		(start 366.911636 -227.320602)
		(end 366.917732 -227.317046)
		(width 0.0889)
		(layer "In6.Cu")
		(net "DMI_CPU0_PCH_TX_DN<7>")
	)
	(segment
		(start 367.842546 -225.69805)
		(end 367.85042 -225.693478)
		(width 0.0889)
		(layer "In6.Cu")
		(net "DMI_CPU0_PCH_TX_DN<7>")
	)
	(segment
		(start 370.191792 -218.372944)
		(end 370.199158 -218.368626)
		(width 0.0889)
		(layer "In6.Cu")
		(net "DMI_CPU0_PCH_TX_DN<7>")
	)
	(segment
		(start 347.730826 -68.389754)
		(end 347.730826 -65.811908)
		(width 0.14732)
		(layer "In6.Cu")
		(net "DMI_CPU0_PCH_TX_DN<7>")
	)
	(segment
		(start 370.661946 -215.931242)
		(end 370.670836 -215.926162)
		(width 0.0889)
		(layer "In6.Cu")
		(net "DMI_CPU0_PCH_TX_DN<7>")
	)
	(segment
		(start 371.935248 -209.619088)
		(end 372.166134 -208.307686)
		(width 0.14732)
		(layer "In6.Cu")
		(net "DMI_CPU0_PCH_TX_DN<7>")
	)
	(segment
		(start 369.252246 -220.000576)
		(end 369.260374 -219.996004)
		(width 0.0889)
		(layer "In6.Cu")
		(net "DMI_CPU0_PCH_TX_DN<7>")
	)
	(segment
		(start 369.260374 -219.996004)
		(end 369.261136 -219.995496)
		(width 0.0889)
		(layer "In6.Cu")
		(net "DMI_CPU0_PCH_TX_DN<7>")
	)
	(segment
		(start 369.722146 -219.18676)
		(end 369.731036 -219.18168)
		(width 0.0889)
		(layer "In6.Cu")
		(net "DMI_CPU0_PCH_TX_DN<7>")
	)
	(segment
		(start 370.200682 -216.739978)
		(end 370.201444 -216.73947)
		(width 0.0889)
		(layer "In6.Cu")
		(net "DMI_CPU0_PCH_TX_DN<7>")
	)
	(segment
		(start 376.653552 -201.89952)
		(end 380.476506 -199.223122)
		(width 0.14732)
		(layer "In6.Cu")
		(net "DMI_CPU0_PCH_TX_DN<7>")
	)
	(segment
		(start 370.483384 -217.878406)
		(end 370.483384 -217.864182)
		(width 0.0889)
		(layer "In6.Cu")
		(net "DMI_CPU0_PCH_TX_DN<7>")
	)
	(segment
		(start 371.893338 -211.535518)
		(end 371.935248 -211.493608)
		(width 0.0889)
		(layer "In6.Cu")
		(net "DMI_CPU0_PCH_TX_DN<7>")
	)
	(segment
		(start 372.166134 -208.307686)
		(end 376.653552 -201.89952)
		(width 0.14732)
		(layer "In6.Cu")
		(net "DMI_CPU0_PCH_TX_DN<7>")
	)
	(segment
		(start 370.201444 -218.367356)
		(end 370.206778 -218.364308)
		(width 0.0889)
		(layer "In6.Cu")
		(net "DMI_CPU0_PCH_TX_DN<7>")
	)
	(segment
		(start 387.618224 -191.24803)
		(end 387.846316 -190.922656)
		(width 0.14732)
		(layer "In6.Cu")
		(net "DMI_CPU0_PCH_TX_DN<7>")
	)
	(segment
		(start 370.95303 -215.452198)
		(end 370.95303 -215.436704)
		(width 0.0889)
		(layer "In6.Cu")
		(net "DMI_CPU0_PCH_TX_DN<7>")
	)
	(segment
		(start 368.13363 -225.225356)
		(end 368.13363 -225.187764)
		(width 0.0889)
		(layer "In6.Cu")
		(net "DMI_CPU0_PCH_TX_DN<7>")
	)
	(segment
		(start 369.543584 -221.133924)
		(end 369.543584 -221.115382)
		(width 0.0889)
		(layer "In6.Cu")
		(net "DMI_CPU0_PCH_TX_DN<7>")
	)
	(segment
		(start 370.013484 -217.072972)
		(end 370.013484 -217.0557)
		(width 0.0889)
		(layer "In6.Cu")
		(net "DMI_CPU0_PCH_TX_DN<7>")
	)
	(segment
		(start 367.663984 -226.027234)
		(end 367.663984 -226.017328)
		(width 0.0889)
		(layer "In6.Cu")
		(net "DMI_CPU0_PCH_TX_DN<7>")
	)
	(arc
		(start 370.206778 -218.364308)
		(mid 370.409365 -218.157957)
		(end 370.483384 -217.878406)
		(width 0.0889)
		(layer "In6.Cu")
		(net "DMI_CPU0_PCH_TX_DN<7>")
	)
	(arc
		(start 368.13363 -225.187764)
		(mid 368.05426 -224.91403)
		(end 367.851436 -224.7138)
		(width 0.0889)
		(layer "In6.Cu")
		(net "DMI_CPU0_PCH_TX_DN<7>")
	)
	(arc
		(start 367.842546 -224.70872)
		(mid 367.714227 -224.576748)
		(end 367.664238 -224.399602)
		(width 0.0889)
		(layer "In6.Cu")
		(net "DMI_CPU0_PCH_TX_DN<7>")
	)
	(arc
		(start 370.483384 -217.864182)
		(mid 370.404165 -217.589497)
		(end 370.200682 -217.388694)
		(width 0.0889)
		(layer "In6.Cu")
		(net "DMI_CPU0_PCH_TX_DN<7>")
	)
	(arc
		(start 366.404398 -227.35032)
		(mid 366.414265 -227.354479)
		(end 366.42421 -227.358448)
		(width 0.0889)
		(layer "In6.Cu")
		(net "DMI_CPU0_PCH_TX_DN<7>")
	)
	(arc
		(start 371.13972 -215.112092)
		(mid 371.201204 -215.071097)
		(end 371.256814 -215.02243)
		(width 0.0889)
		(layer "In6.Cu")
		(net "DMI_CPU0_PCH_TX_DN<7>")
	)
	(arc
		(start 369.731036 -219.18168)
		(mid 369.933859 -218.981449)
		(end 370.01323 -218.707716)
		(width 0.0889)
		(layer "In6.Cu")
		(net "DMI_CPU0_PCH_TX_DN<7>")
	)
	(arc
		(start 369.252246 -220.639132)
		(mid 369.073649 -220.319854)
		(end 369.252246 -220.000576)
		(width 0.0889)
		(layer "In6.Cu")
		(net "DMI_CPU0_PCH_TX_DN<7>")
	)
	(arc
		(start 370.013484 -217.0557)
		(mid 370.065754 -216.873335)
		(end 370.200682 -216.739978)
		(width 0.0889)
		(layer "In6.Cu")
		(net "DMI_CPU0_PCH_TX_DN<7>")
	)
	(arc
		(start 370.01323 -218.692222)
		(mid 370.060909 -218.509322)
		(end 370.191792 -218.372944)
		(width 0.0889)
		(layer "In6.Cu")
		(net "DMI_CPU0_PCH_TX_DN<7>")
	)
	(arc
		(start 366.42421 -227.358448)
		(mid 366.672221 -227.394913)
		(end 366.911636 -227.320602)
		(width 0.0889)
		(layer "In6.Cu")
		(net "DMI_CPU0_PCH_TX_DN<7>")
	)
	(arc
		(start 367.664238 -226.002596)
		(mid 367.715292 -225.828016)
		(end 367.842546 -225.69805)
		(width 0.0889)
		(layer "In6.Cu")
		(net "DMI_CPU0_PCH_TX_DN<7>")
	)
	(arc
		(start 369.543584 -221.115382)
		(mid 369.463422 -220.843193)
		(end 369.261136 -220.644212)
		(width 0.0889)
		(layer "In6.Cu")
		(net "DMI_CPU0_PCH_TX_DN<7>")
	)
	(arc
		(start 370.206778 -216.736422)
		(mid 370.409365 -216.530071)
		(end 370.483384 -216.25052)
		(width 0.0889)
		(layer "In6.Cu")
		(net "DMI_CPU0_PCH_TX_DN<7>")
	)
	(arc
		(start 368.603784 -222.761556)
		(mid 368.651463 -222.578656)
		(end 368.782346 -222.442278)
		(width 0.0889)
		(layer "In6.Cu")
		(net "DMI_CPU0_PCH_TX_DN<7>")
	)
	(arc
		(start 367.851436 -225.69297)
		(mid 368.052718 -225.495483)
		(end 368.13363 -225.225356)
		(width 0.0889)
		(layer "In6.Cu")
		(net "DMI_CPU0_PCH_TX_DN<7>")
	)
	(arc
		(start 368.133884 -223.56699)
		(mid 368.186154 -223.384625)
		(end 368.321082 -223.251268)
		(width 0.0889)
		(layer "In6.Cu")
		(net "DMI_CPU0_PCH_TX_DN<7>")
	)
	(arc
		(start 370.95303 -215.436704)
		(mid 371.000709 -215.253804)
		(end 371.131592 -215.117426)
		(width 0.0889)
		(layer "In6.Cu")
		(net "DMI_CPU0_PCH_TX_DN<7>")
	)
	(arc
		(start 368.791236 -222.437198)
		(mid 368.994059 -222.236967)
		(end 369.07343 -221.963234)
		(width 0.0889)
		(layer "In6.Cu")
		(net "DMI_CPU0_PCH_TX_DN<7>")
	)
	(arc
		(start 370.483384 -216.25052)
		(mid 370.531063 -216.06762)
		(end 370.661946 -215.931242)
		(width 0.0889)
		(layer "In6.Cu")
		(net "DMI_CPU0_PCH_TX_DN<7>")
	)
	(arc
		(start 369.266978 -221.619826)
		(mid 369.469565 -221.413475)
		(end 369.543584 -221.133924)
		(width 0.0889)
		(layer "In6.Cu")
		(net "DMI_CPU0_PCH_TX_DN<7>")
	)
	(arc
		(start 367.194084 -226.831144)
		(mid 367.241763 -226.648244)
		(end 367.372646 -226.511866)
		(width 0.0889)
		(layer "In6.Cu")
		(net "DMI_CPU0_PCH_TX_DN<7>")
	)
	(arc
		(start 368.321082 -223.251268)
		(mid 368.524563 -223.050464)
		(end 368.603784 -222.77578)
		(width 0.0889)
		(layer "In6.Cu")
		(net "DMI_CPU0_PCH_TX_DN<7>")
	)
	(arc
		(start 370.200682 -217.388694)
		(mid 370.065749 -217.25534)
		(end 370.013484 -217.072972)
		(width 0.0889)
		(layer "In6.Cu")
		(net "DMI_CPU0_PCH_TX_DN<7>")
	)
	(arc
		(start 367.381536 -226.506786)
		(mid 367.585871 -226.304181)
		(end 367.663984 -226.027234)
		(width 0.0889)
		(layer "In6.Cu")
		(net "DMI_CPU0_PCH_TX_DN<7>")
	)
	(arc
		(start 367.851436 -224.065084)
		(mid 368.055771 -223.862479)
		(end 368.133884 -223.585532)
		(width 0.0889)
		(layer "In6.Cu")
		(net "DMI_CPU0_PCH_TX_DN<7>")
	)
	(arc
		(start 367.663984 -226.017328)
		(mid 367.664036 -226.009961)
		(end 367.664238 -226.002596)
		(width 0.0889)
		(layer "In6.Cu")
		(net "DMI_CPU0_PCH_TX_DN<7>")
	)
	(arc
		(start 369.543584 -219.506038)
		(mid 369.591263 -219.323138)
		(end 369.722146 -219.18676)
		(width 0.0889)
		(layer "In6.Cu")
		(net "DMI_CPU0_PCH_TX_DN<7>")
	)
	(arc
		(start 369.07343 -221.94774)
		(mid 369.121109 -221.76484)
		(end 369.251992 -221.628462)
		(width 0.0889)
		(layer "In6.Cu")
		(net "DMI_CPU0_PCH_TX_DN<7>")
	)
	(arc
		(start 370.670836 -215.926162)
		(mid 370.873659 -215.725931)
		(end 370.95303 -215.452198)
		(width 0.0889)
		(layer "In6.Cu")
		(net "DMI_CPU0_PCH_TX_DN<7>")
	)
	(arc
		(start 367.664238 -224.382838)
		(mid 367.713345 -224.203649)
		(end 367.842546 -224.070164)
		(width 0.0889)
		(layer "In6.Cu")
		(net "DMI_CPU0_PCH_TX_DN<7>")
	)
	(arc
		(start 367.664238 -224.399602)
		(mid 367.664144 -224.39122)
		(end 367.664238 -224.382838)
		(width 0.0889)
		(layer "In6.Cu")
		(net "DMI_CPU0_PCH_TX_DN<7>")
	)
	(arc
		(start 366.917732 -227.317046)
		(mid 367.120145 -227.110633)
		(end 367.194084 -226.831144)
		(width 0.0889)
		(layer "In6.Cu")
		(net "DMI_CPU0_PCH_TX_DN<7>")
	)
	(arc
		(start 369.261136 -219.995496)
		(mid 369.465471 -219.792891)
		(end 369.543584 -219.515944)
		(width 0.0889)
		(layer "In6.Cu")
		(net "DMI_CPU0_PCH_TX_DN<7>")
	)
	(segment
		(start 365.219234 -228.180646)
		(end 365.219234 -227.64496)
		(width 0.13208)
		(layer "F.Cu")
		(net "DMI_CPU0_PCH_TX_DN<6>")
	)
	(segment
		(start 349.66148 -62.708028)
		(end 350.3803 -62.708028)
		(width 0.13208)
		(layer "F.Cu")
		(net "DMI_CPU0_PCH_TX_DN<6>")
	)
	(segment
		(start 365.21898 -228.1809)
		(end 365.219234 -228.180646)
		(width 0.13208)
		(layer "F.Cu")
		(net "DMI_CPU0_PCH_TX_DN<6>")
	)
	(segment
		(start 350.3803 -62.708028)
		(end 350.682052 -62.406276)
		(width 0.13208)
		(layer "F.Cu")
		(net "DMI_CPU0_PCH_TX_DN<6>")
	)
	(segment
		(start 349.3516 -62.398148)
		(end 349.66148 -62.708028)
		(width 0.13208)
		(layer "F.Cu")
		(net "DMI_CPU0_PCH_TX_DN<6>")
	)
	(segment
		(start 367.286032 -223.085914)
		(end 367.294922 -223.080834)
		(width 0.0889)
		(layer "In6.Cu")
		(net "DMI_CPU0_PCH_TX_DN<6>")
	)
	(segment
		(start 388.745222 -178.237134)
		(end 383.383028 -147.830794)
		(width 0.14732)
		(layer "In6.Cu")
		(net "DMI_CPU0_PCH_TX_DN<6>")
	)
	(segment
		(start 370.655088 -213.157816)
		(end 370.655088 -212.893656)
		(width 0.0889)
		(layer "In6.Cu")
		(net "DMI_CPU0_PCH_TX_DN<6>")
	)
	(segment
		(start 368.22634 -221.457774)
		(end 368.228118 -221.456758)
		(width 0.0889)
		(layer "In6.Cu")
		(net "DMI_CPU0_PCH_TX_DN<6>")
	)
	(segment
		(start 369.17249 -218.198954)
		(end 369.174522 -218.197684)
		(width 0.0889)
		(layer "In6.Cu")
		(net "DMI_CPU0_PCH_TX_DN<6>")
	)
	(segment
		(start 366.06353 -226.83978)
		(end 366.06353 -226.831144)
		(width 0.0889)
		(layer "In6.Cu")
		(net "DMI_CPU0_PCH_TX_DN<6>")
	)
	(segment
		(start 350.4057 -62.682628)
		(end 350.682052 -62.406276)
		(width 0.14732)
		(layer "In6.Cu")
		(net "DMI_CPU0_PCH_TX_DN<6>")
	)
	(segment
		(start 350.298258 -80.503522)
		(end 348.858078 -75.89012)
		(width 0.14732)
		(layer "In6.Cu")
		(net "DMI_CPU0_PCH_TX_DN<6>")
	)
	(segment
		(start 370.754148 -214.316564)
		(end 370.754148 -213.983316)
		(width 0.0889)
		(layer "In6.Cu")
		(net "DMI_CPU0_PCH_TX_DN<6>")
	)
	(segment
		(start 370.754148 -213.983316)
		(end 370.655088 -213.884256)
		(width 0.0889)
		(layer "In6.Cu")
		(net "DMI_CPU0_PCH_TX_DN<6>")
	)
	(segment
		(start 368.219736 -219.833952)
		(end 368.234722 -219.825316)
		(width 0.0889)
		(layer "In6.Cu")
		(net "DMI_CPU0_PCH_TX_DN<6>")
	)
	(segment
		(start 368.225578 -221.458282)
		(end 368.22634 -221.457774)
		(width 0.0889)
		(layer "In6.Cu")
		(net "DMI_CPU0_PCH_TX_DN<6>")
	)
	(segment
		(start 369.174522 -217.559128)
		(end 369.166394 -217.554556)
		(width 0.0889)
		(layer "In6.Cu")
		(net "DMI_CPU0_PCH_TX_DN<6>")
	)
	(segment
		(start 366.533684 -224.404936)
		(end 366.533684 -224.373948)
		(width 0.0889)
		(layer "In6.Cu")
		(net "DMI_CPU0_PCH_TX_DN<6>")
	)
	(segment
		(start 346.559378 -68.78955)
		(end 346.559378 -65.20307)
		(width 0.14732)
		(layer "In6.Cu")
		(net "DMI_CPU0_PCH_TX_DN<6>")
	)
	(segment
		(start 386.83311 -189.084458)
		(end 388.745222 -178.237134)
		(width 0.14732)
		(layer "In6.Cu")
		(net "DMI_CPU0_PCH_TX_DN<6>")
	)
	(segment
		(start 370.711984 -211.798408)
		(end 370.711984 -211.77631)
		(width 0.0889)
		(layer "In6.Cu")
		(net "DMI_CPU0_PCH_TX_DN<6>")
	)
	(segment
		(start 366.815878 -223.899984)
		(end 366.824768 -223.894904)
		(width 0.0889)
		(layer "In6.Cu")
		(net "DMI_CPU0_PCH_TX_DN<6>")
	)
	(segment
		(start 370.98351 -207.970628)
		(end 375.746264 -201.168762)
		(width 0.14732)
		(layer "In6.Cu")
		(net "DMI_CPU0_PCH_TX_DN<6>")
	)
	(segment
		(start 370.754148 -213.521036)
		(end 370.754148 -213.256876)
		(width 0.0889)
		(layer "In6.Cu")
		(net "DMI_CPU0_PCH_TX_DN<6>")
	)
	(segment
		(start 370.754148 -211.840572)
		(end 370.711984 -211.798408)
		(width 0.0889)
		(layer "In6.Cu")
		(net "DMI_CPU0_PCH_TX_DN<6>")
	)
	(segment
		(start 367.473484 -222.761556)
		(end 367.473484 -222.75165)
		(width 0.0889)
		(layer "In6.Cu")
		(net "DMI_CPU0_PCH_TX_DN<6>")
	)
	(segment
		(start 368.234468 -220.814646)
		(end 368.225578 -220.809566)
		(width 0.0889)
		(layer "In6.Cu")
		(net "DMI_CPU0_PCH_TX_DN<6>")
	)
	(segment
		(start 381.798322 -196.275198)
		(end 386.83311 -189.084458)
		(width 0.14732)
		(layer "In6.Cu")
		(net "DMI_CPU0_PCH_TX_DN<6>")
	)
	(segment
		(start 346.559378 -65.20307)
		(end 349.07982 -62.682628)
		(width 0.14732)
		(layer "In6.Cu")
		(net "DMI_CPU0_PCH_TX_DN<6>")
	)
	(segment
		(start 383.383028 -147.830794)
		(end 350.298258 -80.503522)
		(width 0.14732)
		(layer "In6.Cu")
		(net "DMI_CPU0_PCH_TX_DN<6>")
	)
	(segment
		(start 366.533684 -226.017328)
		(end 366.533684 -225.99523)
		(width 0.0889)
		(layer "In6.Cu")
		(net "DMI_CPU0_PCH_TX_DN<6>")
	)
	(segment
		(start 368.233706 -221.45371)
		(end 368.234468 -221.453202)
		(width 0.0889)
		(layer "In6.Cu")
		(net "DMI_CPU0_PCH_TX_DN<6>")
	)
	(segment
		(start 370.711984 -209.511646)
		(end 370.98351 -207.970628)
		(width 0.14732)
		(layer "In6.Cu")
		(net "DMI_CPU0_PCH_TX_DN<6>")
	)
	(segment
		(start 370.099336 -214.950802)
		(end 370.105432 -214.947246)
		(width 0.0889)
		(layer "In6.Cu")
		(net "DMI_CPU0_PCH_TX_DN<6>")
	)
	(segment
		(start 370.655088 -213.884256)
		(end 370.655088 -213.620096)
		(width 0.0889)
		(layer "In6.Cu")
		(net "DMI_CPU0_PCH_TX_DN<6>")
	)
	(segment
		(start 369.166394 -217.554556)
		(end 369.165632 -217.554048)
		(width 0.0889)
		(layer "In6.Cu")
		(net "DMI_CPU0_PCH_TX_DN<6>")
	)
	(segment
		(start 379.61062 -198.4629)
		(end 381.798322 -196.275198)
		(width 0.14732)
		(layer "In6.Cu")
		(net "DMI_CPU0_PCH_TX_DN<6>")
	)
	(segment
		(start 369.159536 -218.20632)
		(end 369.17249 -218.198954)
		(width 0.0889)
		(layer "In6.Cu")
		(net "DMI_CPU0_PCH_TX_DN<6>")
	)
	(segment
		(start 369.15344 -216.58199)
		(end 369.174522 -216.569798)
		(width 0.0889)
		(layer "In6.Cu")
		(net "DMI_CPU0_PCH_TX_DN<6>")
	)
	(segment
		(start 365.375698 -227.915978)
		(end 365.45393 -227.936806)
		(width 0.0889)
		(layer "In6.Cu")
		(net "DMI_CPU0_PCH_TX_DN<6>")
	)
	(segment
		(start 366.824768 -224.88398)
		(end 366.815878 -224.8789)
		(width 0.0889)
		(layer "In6.Cu")
		(net "DMI_CPU0_PCH_TX_DN<6>")
	)
	(segment
		(start 368.413284 -219.506038)
		(end 368.413284 -219.490544)
		(width 0.0889)
		(layer "In6.Cu")
		(net "DMI_CPU0_PCH_TX_DN<6>")
	)
	(segment
		(start 369.82273 -215.44534)
		(end 369.82273 -215.436704)
		(width 0.0889)
		(layer "In6.Cu")
		(net "DMI_CPU0_PCH_TX_DN<6>")
	)
	(segment
		(start 370.655088 -212.893656)
		(end 370.754148 -212.794596)
		(width 0.0889)
		(layer "In6.Cu")
		(net "DMI_CPU0_PCH_TX_DN<6>")
	)
	(segment
		(start 366.340136 -226.345242)
		(end 366.355122 -226.336606)
		(width 0.0889)
		(layer "In6.Cu")
		(net "DMI_CPU0_PCH_TX_DN<6>")
	)
	(segment
		(start 375.746264 -201.168762)
		(end 379.61062 -198.4629)
		(width 0.14732)
		(layer "In6.Cu")
		(net "DMI_CPU0_PCH_TX_DN<6>")
	)
	(segment
		(start 370.655088 -213.620096)
		(end 370.754148 -213.521036)
		(width 0.0889)
		(layer "In6.Cu")
		(net "DMI_CPU0_PCH_TX_DN<6>")
	)
	(segment
		(start 367.00333 -223.575626)
		(end 367.00333 -223.568006)
		(width 0.0889)
		(layer "In6.Cu")
		(net "DMI_CPU0_PCH_TX_DN<6>")
	)
	(segment
		(start 367.94313 -220.338396)
		(end 367.94313 -220.319854)
		(width 0.0889)
		(layer "In6.Cu")
		(net "DMI_CPU0_PCH_TX_DN<6>")
	)
	(segment
		(start 365.593884 -227.64496)
		(end 365.593884 -227.635054)
		(width 0.0889)
		(layer "In6.Cu")
		(net "DMI_CPU0_PCH_TX_DN<6>")
	)
	(segment
		(start 349.07982 -62.682628)
		(end 350.4057 -62.682628)
		(width 0.14732)
		(layer "In6.Cu")
		(net "DMI_CPU0_PCH_TX_DN<6>")
	)
	(segment
		(start 370.183156 -214.887556)
		(end 370.754148 -214.316564)
		(width 0.0889)
		(layer "In6.Cu")
		(net "DMI_CPU0_PCH_TX_DN<6>")
	)
	(segment
		(start 368.695478 -219.01658)
		(end 368.704368 -219.0115)
		(width 0.0889)
		(layer "In6.Cu")
		(net "DMI_CPU0_PCH_TX_DN<6>")
	)
	(segment
		(start 369.353084 -216.25052)
		(end 369.353084 -216.240614)
		(width 0.0889)
		(layer "In6.Cu")
		(net "DMI_CPU0_PCH_TX_DN<6>")
	)
	(segment
		(start 348.858078 -72.004936)
		(end 348.209616 -70.439788)
		(width 0.14732)
		(layer "In6.Cu")
		(net "DMI_CPU0_PCH_TX_DN<6>")
	)
	(segment
		(start 348.209616 -70.439788)
		(end 346.559378 -68.78955)
		(width 0.14732)
		(layer "In6.Cu")
		(net "DMI_CPU0_PCH_TX_DN<6>")
	)
	(segment
		(start 366.815878 -225.527616)
		(end 366.824768 -225.522536)
		(width 0.0889)
		(layer "In6.Cu")
		(net "DMI_CPU0_PCH_TX_DN<6>")
	)
	(segment
		(start 365.219234 -227.64496)
		(end 365.375698 -227.915978)
		(width 0.0889)
		(layer "In6.Cu")
		(net "DMI_CPU0_PCH_TX_DN<6>")
	)
	(segment
		(start 370.754148 -213.256876)
		(end 370.655088 -213.157816)
		(width 0.0889)
		(layer "In6.Cu")
		(net "DMI_CPU0_PCH_TX_DN<6>")
	)
	(segment
		(start 348.858078 -75.89012)
		(end 348.858078 -72.004936)
		(width 0.14732)
		(layer "In6.Cu")
		(net "DMI_CPU0_PCH_TX_DN<6>")
	)
	(segment
		(start 370.711984 -211.77631)
		(end 370.711984 -209.511646)
		(width 0.14732)
		(layer "In6.Cu")
		(net "DMI_CPU0_PCH_TX_DN<6>")
	)
	(segment
		(start 370.754148 -212.794596)
		(end 370.754148 -211.840572)
		(width 0.0889)
		(layer "In6.Cu")
		(net "DMI_CPU0_PCH_TX_DN<6>")
	)
	(segment
		(start 368.22888 -221.45625)
		(end 368.233706 -221.45371)
		(width 0.0889)
		(layer "In6.Cu")
		(net "DMI_CPU0_PCH_TX_DN<6>")
	)
	(segment
		(start 367.94313 -221.956376)
		(end 367.94313 -221.937834)
		(width 0.0889)
		(layer "In6.Cu")
		(net "DMI_CPU0_PCH_TX_DN<6>")
	)
	(segment
		(start 368.228118 -221.456758)
		(end 368.22888 -221.45625)
		(width 0.0889)
		(layer "In6.Cu")
		(net "DMI_CPU0_PCH_TX_DN<6>")
	)
	(arc
		(start 367.755932 -222.272098)
		(mid 367.890865 -222.138744)
		(end 367.94313 -221.956376)
		(width 0.0889)
		(layer "In6.Cu")
		(net "DMI_CPU0_PCH_TX_DN<6>")
	)
	(arc
		(start 367.00333 -225.193098)
		(mid 366.953261 -225.015873)
		(end 366.824768 -224.88398)
		(width 0.0889)
		(layer "In6.Cu")
		(net "DMI_CPU0_PCH_TX_DN<6>")
	)
	(arc
		(start 365.593884 -227.635054)
		(mid 365.671995 -227.358105)
		(end 365.876332 -227.155502)
		(width 0.0889)
		(layer "In6.Cu")
		(net "DMI_CPU0_PCH_TX_DN<6>")
	)
	(arc
		(start 369.82273 -215.436704)
		(mid 369.896721 -215.157138)
		(end 370.099336 -214.950802)
		(width 0.0889)
		(layer "In6.Cu")
		(net "DMI_CPU0_PCH_TX_DN<6>")
	)
	(arc
		(start 369.174522 -216.569798)
		(mid 369.305436 -216.433438)
		(end 369.353084 -216.25052)
		(width 0.0889)
		(layer "In6.Cu")
		(net "DMI_CPU0_PCH_TX_DN<6>")
	)
	(arc
		(start 366.824768 -225.522536)
		(mid 366.952022 -225.39257)
		(end 367.003076 -225.21799)
		(width 0.0889)
		(layer "In6.Cu")
		(net "DMI_CPU0_PCH_TX_DN<6>")
	)
	(arc
		(start 366.533684 -225.99523)
		(mid 366.614595 -225.725102)
		(end 366.815878 -225.527616)
		(width 0.0889)
		(layer "In6.Cu")
		(net "DMI_CPU0_PCH_TX_DN<6>")
	)
	(arc
		(start 368.704368 -219.0115)
		(mid 368.835282 -218.87514)
		(end 368.88293 -218.692222)
		(width 0.0889)
		(layer "In6.Cu")
		(net "DMI_CPU0_PCH_TX_DN<6>")
	)
	(arc
		(start 367.473484 -222.75165)
		(mid 367.551595 -222.474701)
		(end 367.755932 -222.272098)
		(width 0.0889)
		(layer "In6.Cu")
		(net "DMI_CPU0_PCH_TX_DN<6>")
	)
	(arc
		(start 366.824768 -223.894904)
		(mid 366.955682 -223.758544)
		(end 367.00333 -223.575626)
		(width 0.0889)
		(layer "In6.Cu")
		(net "DMI_CPU0_PCH_TX_DN<6>")
	)
	(arc
		(start 366.815878 -224.8789)
		(mid 366.613055 -224.678669)
		(end 366.533684 -224.404936)
		(width 0.0889)
		(layer "In6.Cu")
		(net "DMI_CPU0_PCH_TX_DN<6>")
	)
	(arc
		(start 366.06353 -226.831144)
		(mid 366.137521 -226.551578)
		(end 366.340136 -226.345242)
		(width 0.0889)
		(layer "In6.Cu")
		(net "DMI_CPU0_PCH_TX_DN<6>")
	)
	(arc
		(start 367.003076 -225.21799)
		(mid 367.003409 -225.205546)
		(end 367.00333 -225.193098)
		(width 0.0889)
		(layer "In6.Cu")
		(net "DMI_CPU0_PCH_TX_DN<6>")
	)
	(arc
		(start 366.355122 -226.336606)
		(mid 366.486036 -226.200246)
		(end 366.533684 -226.017328)
		(width 0.0889)
		(layer "In6.Cu")
		(net "DMI_CPU0_PCH_TX_DN<6>")
	)
	(arc
		(start 370.105432 -214.947246)
		(mid 370.146245 -214.919943)
		(end 370.183156 -214.887556)
		(width 0.0889)
		(layer "In6.Cu")
		(net "DMI_CPU0_PCH_TX_DN<6>")
	)
	(arc
		(start 369.635532 -215.761062)
		(mid 369.770465 -215.627708)
		(end 369.82273 -215.44534)
		(width 0.0889)
		(layer "In6.Cu")
		(net "DMI_CPU0_PCH_TX_DN<6>")
	)
	(arc
		(start 365.45393 -227.936806)
		(mid 365.557075 -227.806781)
		(end 365.593884 -227.64496)
		(width 0.0889)
		(layer "In6.Cu")
		(net "DMI_CPU0_PCH_TX_DN<6>")
	)
	(arc
		(start 368.88293 -218.692222)
		(mid 368.956921 -218.412656)
		(end 369.159536 -218.20632)
		(width 0.0889)
		(layer "In6.Cu")
		(net "DMI_CPU0_PCH_TX_DN<6>")
	)
	(arc
		(start 369.353084 -216.240614)
		(mid 369.431195 -215.963665)
		(end 369.635532 -215.761062)
		(width 0.0889)
		(layer "In6.Cu")
		(net "DMI_CPU0_PCH_TX_DN<6>")
	)
	(arc
		(start 366.533684 -224.373948)
		(mid 366.613054 -224.100214)
		(end 366.815878 -223.899984)
		(width 0.0889)
		(layer "In6.Cu")
		(net "DMI_CPU0_PCH_TX_DN<6>")
	)
	(arc
		(start 369.174522 -218.197684)
		(mid 369.353119 -217.878406)
		(end 369.174522 -217.559128)
		(width 0.0889)
		(layer "In6.Cu")
		(net "DMI_CPU0_PCH_TX_DN<6>")
	)
	(arc
		(start 368.413284 -219.490544)
		(mid 368.492654 -219.21681)
		(end 368.695478 -219.01658)
		(width 0.0889)
		(layer "In6.Cu")
		(net "DMI_CPU0_PCH_TX_DN<6>")
	)
	(arc
		(start 368.234722 -219.825316)
		(mid 368.365636 -219.688956)
		(end 368.413284 -219.506038)
		(width 0.0889)
		(layer "In6.Cu")
		(net "DMI_CPU0_PCH_TX_DN<6>")
	)
	(arc
		(start 368.225578 -220.809566)
		(mid 368.023292 -220.610585)
		(end 367.94313 -220.338396)
		(width 0.0889)
		(layer "In6.Cu")
		(net "DMI_CPU0_PCH_TX_DN<6>")
	)
	(arc
		(start 365.876332 -227.155502)
		(mid 366.011265 -227.022148)
		(end 366.06353 -226.83978)
		(width 0.0889)
		(layer "In6.Cu")
		(net "DMI_CPU0_PCH_TX_DN<6>")
	)
	(arc
		(start 368.234468 -221.453202)
		(mid 368.413065 -221.133924)
		(end 368.234468 -220.814646)
		(width 0.0889)
		(layer "In6.Cu")
		(net "DMI_CPU0_PCH_TX_DN<6>")
	)
	(arc
		(start 367.294922 -223.080834)
		(mid 367.425836 -222.944474)
		(end 367.473484 -222.761556)
		(width 0.0889)
		(layer "In6.Cu")
		(net "DMI_CPU0_PCH_TX_DN<6>")
	)
	(arc
		(start 369.165632 -217.554048)
		(mid 368.882798 -217.071459)
		(end 369.15344 -216.58199)
		(width 0.0889)
		(layer "In6.Cu")
		(net "DMI_CPU0_PCH_TX_DN<6>")
	)
	(arc
		(start 367.94313 -221.937834)
		(mid 368.021241 -221.660885)
		(end 368.225578 -221.458282)
		(width 0.0889)
		(layer "In6.Cu")
		(net "DMI_CPU0_PCH_TX_DN<6>")
	)
	(arc
		(start 367.00333 -223.568006)
		(mid 367.080959 -223.289593)
		(end 367.286032 -223.085914)
		(width 0.0889)
		(layer "In6.Cu")
		(net "DMI_CPU0_PCH_TX_DN<6>")
	)
	(arc
		(start 367.94313 -220.319854)
		(mid 368.017121 -220.040288)
		(end 368.219736 -219.833952)
		(width 0.0889)
		(layer "In6.Cu")
		(net "DMI_CPU0_PCH_TX_DN<6>")
	)
	(segment
		(start 364.74908 -227.36683)
		(end 364.74908 -226.831144)
		(width 0.13208)
		(layer "F.Cu")
		(net "DMI_CPU0_PCH_TX_DN<5>")
	)
	(segment
		(start 364.749334 -227.367084)
		(end 364.74908 -227.36683)
		(width 0.13208)
		(layer "F.Cu")
		(net "DMI_CPU0_PCH_TX_DN<5>")
	)
	(segment
		(start 352.27133 -64.769492)
		(end 352.439986 -64.769492)
		(width 0.13208)
		(layer "F.Cu")
		(net "DMI_CPU0_PCH_TX_DN<5>")
	)
	(segment
		(start 352.439986 -64.769492)
		(end 352.743516 -64.465962)
		(width 0.13208)
		(layer "F.Cu")
		(net "DMI_CPU0_PCH_TX_DN<5>")
	)
	(segment
		(start 351.9424 -64.440562)
		(end 352.27133 -64.769492)
		(width 0.13208)
		(layer "F.Cu")
		(net "DMI_CPU0_PCH_TX_DN<5>")
	)
	(segment
		(start 372.631716 -212.251544)
		(end 372.589806 -212.209634)
		(width 0.0889)
		(layer "In6.Cu")
		(net "DMI_CPU0_PCH_TX_DN<5>")
	)
	(segment
		(start 369.353084 -222.761556)
		(end 369.353084 -222.746062)
		(width 0.0889)
		(layer "In6.Cu")
		(net "DMI_CPU0_PCH_TX_DN<5>")
	)
	(segment
		(start 368.704368 -224.88398)
		(end 368.696494 -224.879408)
		(width 0.0889)
		(layer "In6.Cu")
		(net "DMI_CPU0_PCH_TX_DN<5>")
	)
	(segment
		(start 371.978936 -214.950802)
		(end 371.985032 -214.947246)
		(width 0.0889)
		(layer "In6.Cu")
		(net "DMI_CPU0_PCH_TX_DN<5>")
	)
	(segment
		(start 369.165632 -223.085914)
		(end 369.174522 -223.080834)
		(width 0.0889)
		(layer "In6.Cu")
		(net "DMI_CPU0_PCH_TX_DN<5>")
	)
	(segment
		(start 384.908806 -146.042634)
		(end 352.55581 -79.82712)
		(width 0.14732)
		(layer "In6.Cu")
		(net "DMI_CPU0_PCH_TX_DN<5>")
	)
	(segment
		(start 367.473484 -227.64496)
		(end 367.473484 -227.635054)
		(width 0.0889)
		(layer "In6.Cu")
		(net "DMI_CPU0_PCH_TX_DN<5>")
	)
	(segment
		(start 369.82273 -220.334078)
		(end 369.82273 -220.319854)
		(width 0.0889)
		(layer "In6.Cu")
		(net "DMI_CPU0_PCH_TX_DN<5>")
	)
	(segment
		(start 368.219736 -226.345242)
		(end 368.234722 -226.336606)
		(width 0.0889)
		(layer "In6.Cu")
		(net "DMI_CPU0_PCH_TX_DN<5>")
	)
	(segment
		(start 370.114322 -220.814646)
		(end 370.105432 -220.809566)
		(width 0.0889)
		(layer "In6.Cu")
		(net "DMI_CPU0_PCH_TX_DN<5>")
	)
	(segment
		(start 371.232684 -216.25052)
		(end 371.232684 -216.240614)
		(width 0.0889)
		(layer "In6.Cu")
		(net "DMI_CPU0_PCH_TX_DN<5>")
	)
	(segment
		(start 371.03304 -216.58199)
		(end 371.054122 -216.569798)
		(width 0.0889)
		(layer "In6.Cu")
		(net "DMI_CPU0_PCH_TX_DN<5>")
	)
	(segment
		(start 352.448876 -64.760602)
		(end 352.743516 -64.465962)
		(width 0.14732)
		(layer "In6.Cu")
		(net "DMI_CPU0_PCH_TX_DN<5>")
	)
	(segment
		(start 366.06353 -228.45903)
		(end 366.06353 -228.444806)
		(width 0.0889)
		(layer "In6.Cu")
		(net "DMI_CPU0_PCH_TX_DN<5>")
	)
	(segment
		(start 372.631716 -214.318596)
		(end 372.631716 -213.698074)
		(width 0.0889)
		(layer "In6.Cu")
		(net "DMI_CPU0_PCH_TX_DN<5>")
	)
	(segment
		(start 372.631716 -213.235794)
		(end 372.631716 -212.849714)
		(width 0.0889)
		(layer "In6.Cu")
		(net "DMI_CPU0_PCH_TX_DN<5>")
	)
	(segment
		(start 351.50552 -64.760602)
		(end 352.448876 -64.760602)
		(width 0.14732)
		(layer "In6.Cu")
		(net "DMI_CPU0_PCH_TX_DN<5>")
	)
	(segment
		(start 370.099336 -219.833952)
		(end 370.105432 -219.830396)
		(width 0.0889)
		(layer "In6.Cu")
		(net "DMI_CPU0_PCH_TX_DN<5>")
	)
	(segment
		(start 365.31423 -228.436932)
		(end 365.31423 -228.45903)
		(width 0.0889)
		(layer "In6.Cu")
		(net "DMI_CPU0_PCH_TX_DN<5>")
	)
	(segment
		(start 370.102638 -221.459806)
		(end 370.105432 -221.458282)
		(width 0.0889)
		(layer "In6.Cu")
		(net "DMI_CPU0_PCH_TX_DN<5>")
	)
	(segment
		(start 372.589806 -211.342986)
		(end 372.589552 -211.342732)
		(width 0.14732)
		(layer "In6.Cu")
		(net "DMI_CPU0_PCH_TX_DN<5>")
	)
	(segment
		(start 371.70233 -215.44534)
		(end 371.70233 -215.436704)
		(width 0.0889)
		(layer "In6.Cu")
		(net "DMI_CPU0_PCH_TX_DN<5>")
	)
	(segment
		(start 372.532656 -213.334854)
		(end 372.631716 -213.235794)
		(width 0.0889)
		(layer "In6.Cu")
		(net "DMI_CPU0_PCH_TX_DN<5>")
	)
	(segment
		(start 387.852158 -191.88303)
		(end 388.647178 -190.747904)
		(width 0.14732)
		(layer "In6.Cu")
		(net "DMI_CPU0_PCH_TX_DN<5>")
	)
	(segment
		(start 368.695478 -225.527616)
		(end 368.704368 -225.522536)
		(width 0.0889)
		(layer "In6.Cu")
		(net "DMI_CPU0_PCH_TX_DN<5>")
	)
	(segment
		(start 372.785386 -208.56448)
		(end 377.123198 -202.369674)
		(width 0.14732)
		(layer "In6.Cu")
		(net "DMI_CPU0_PCH_TX_DN<5>")
	)
	(segment
		(start 372.532656 -212.486494)
		(end 372.631716 -212.387434)
		(width 0.0889)
		(layer "In6.Cu")
		(net "DMI_CPU0_PCH_TX_DN<5>")
	)
	(segment
		(start 350.793558 -72.208136)
		(end 349.668338 -69.490336)
		(width 0.14732)
		(layer "In6.Cu")
		(net "DMI_CPU0_PCH_TX_DN<5>")
	)
	(segment
		(start 372.631716 -212.387434)
		(end 372.631716 -212.251544)
		(width 0.0889)
		(layer "In6.Cu")
		(net "DMI_CPU0_PCH_TX_DN<5>")
	)
	(segment
		(start 384.032506 -196.525388)
		(end 386.73532 -192.665096)
		(width 0.14732)
		(layer "In6.Cu")
		(net "DMI_CPU0_PCH_TX_DN<5>")
	)
	(segment
		(start 364.592616 -227.102162)
		(end 364.616746 -227.191316)
		(width 0.0889)
		(layer "In6.Cu")
		(net "DMI_CPU0_PCH_TX_DN<5>")
	)
	(segment
		(start 371.054122 -217.559128)
		(end 371.045994 -217.554556)
		(width 0.0889)
		(layer "In6.Cu")
		(net "DMI_CPU0_PCH_TX_DN<5>")
	)
	(segment
		(start 370.575078 -219.01658)
		(end 370.583968 -219.0115)
		(width 0.0889)
		(layer "In6.Cu")
		(net "DMI_CPU0_PCH_TX_DN<5>")
	)
	(segment
		(start 364.74908 -226.831144)
		(end 364.592616 -227.102162)
		(width 0.0889)
		(layer "In6.Cu")
		(net "DMI_CPU0_PCH_TX_DN<5>")
	)
	(segment
		(start 372.589806 -212.187536)
		(end 372.589806 -211.342986)
		(width 0.14732)
		(layer "In6.Cu")
		(net "DMI_CPU0_PCH_TX_DN<5>")
	)
	(segment
		(start 371.045994 -217.554556)
		(end 371.045232 -217.554048)
		(width 0.0889)
		(layer "In6.Cu")
		(net "DMI_CPU0_PCH_TX_DN<5>")
	)
	(segment
		(start 348.30512 -66.08445)
		(end 349.46082 -64.92875)
		(width 0.14732)
		(layer "In6.Cu")
		(net "DMI_CPU0_PCH_TX_DN<5>")
	)
	(segment
		(start 372.532656 -213.599014)
		(end 372.532656 -213.334854)
		(width 0.0889)
		(layer "In6.Cu")
		(net "DMI_CPU0_PCH_TX_DN<5>")
	)
	(segment
		(start 369.635278 -222.272098)
		(end 369.644168 -222.267018)
		(width 0.0889)
		(layer "In6.Cu")
		(net "DMI_CPU0_PCH_TX_DN<5>")
	)
	(segment
		(start 368.88293 -223.575626)
		(end 368.88293 -223.568006)
		(width 0.0889)
		(layer "In6.Cu")
		(net "DMI_CPU0_PCH_TX_DN<5>")
	)
	(segment
		(start 386.73532 -192.665096)
		(end 387.852158 -191.88303)
		(width 0.14732)
		(layer "In6.Cu")
		(net "DMI_CPU0_PCH_TX_DN<5>")
	)
	(segment
		(start 372.062756 -214.887556)
		(end 372.631716 -214.318596)
		(width 0.0889)
		(layer "In6.Cu")
		(net "DMI_CPU0_PCH_TX_DN<5>")
	)
	(segment
		(start 371.05209 -218.198954)
		(end 371.054122 -218.197684)
		(width 0.0889)
		(layer "In6.Cu")
		(net "DMI_CPU0_PCH_TX_DN<5>")
	)
	(segment
		(start 349.46082 -64.92875)
		(end 351.099374 -64.92875)
		(width 0.14732)
		(layer "In6.Cu")
		(net "DMI_CPU0_PCH_TX_DN<5>")
	)
	(segment
		(start 372.631716 -212.849714)
		(end 372.532656 -212.750654)
		(width 0.0889)
		(layer "In6.Cu")
		(net "DMI_CPU0_PCH_TX_DN<5>")
	)
	(segment
		(start 368.695478 -223.899984)
		(end 368.696494 -223.899476)
		(width 0.0889)
		(layer "In6.Cu")
		(net "DMI_CPU0_PCH_TX_DN<5>")
	)
	(segment
		(start 380.673864 -199.88403)
		(end 384.032506 -196.525388)
		(width 0.14732)
		(layer "In6.Cu")
		(net "DMI_CPU0_PCH_TX_DN<5>")
	)
	(segment
		(start 368.413284 -224.404936)
		(end 368.413284 -224.373948)
		(width 0.0889)
		(layer "In6.Cu")
		(net "DMI_CPU0_PCH_TX_DN<5>")
	)
	(segment
		(start 377.123198 -202.369674)
		(end 380.673864 -199.88403)
		(width 0.14732)
		(layer "In6.Cu")
		(net "DMI_CPU0_PCH_TX_DN<5>")
	)
	(segment
		(start 351.099374 -64.92875)
		(end 351.50552 -64.760602)
		(width 0.14732)
		(layer "In6.Cu")
		(net "DMI_CPU0_PCH_TX_DN<5>")
	)
	(segment
		(start 370.105432 -221.458282)
		(end 370.106956 -221.45752)
		(width 0.0889)
		(layer "In6.Cu")
		(net "DMI_CPU0_PCH_TX_DN<5>")
	)
	(segment
		(start 367.94313 -226.83978)
		(end 367.94313 -226.831144)
		(width 0.0889)
		(layer "In6.Cu")
		(net "DMI_CPU0_PCH_TX_DN<5>")
	)
	(segment
		(start 372.589552 -211.342732)
		(end 372.589552 -209.676492)
		(width 0.14732)
		(layer "In6.Cu")
		(net "DMI_CPU0_PCH_TX_DN<5>")
	)
	(segment
		(start 348.30512 -68.127118)
		(end 348.30512 -66.08445)
		(width 0.14732)
		(layer "In6.Cu")
		(net "DMI_CPU0_PCH_TX_DN<5>")
	)
	(segment
		(start 372.532656 -212.750654)
		(end 372.532656 -212.486494)
		(width 0.0889)
		(layer "In6.Cu")
		(net "DMI_CPU0_PCH_TX_DN<5>")
	)
	(segment
		(start 368.413284 -226.017328)
		(end 368.413284 -225.99523)
		(width 0.0889)
		(layer "In6.Cu")
		(net "DMI_CPU0_PCH_TX_DN<5>")
	)
	(segment
		(start 370.292884 -219.506038)
		(end 370.292884 -219.490544)
		(width 0.0889)
		(layer "In6.Cu")
		(net "DMI_CPU0_PCH_TX_DN<5>")
	)
	(segment
		(start 372.589552 -209.676492)
		(end 372.785386 -208.56448)
		(width 0.14732)
		(layer "In6.Cu")
		(net "DMI_CPU0_PCH_TX_DN<5>")
	)
	(segment
		(start 368.696494 -224.879408)
		(end 368.695478 -224.8789)
		(width 0.0889)
		(layer "In6.Cu")
		(net "DMI_CPU0_PCH_TX_DN<5>")
	)
	(segment
		(start 370.106956 -221.45752)
		(end 370.114322 -221.453202)
		(width 0.0889)
		(layer "In6.Cu")
		(net "DMI_CPU0_PCH_TX_DN<5>")
	)
	(segment
		(start 390.71931 -178.997864)
		(end 384.908806 -146.042634)
		(width 0.14732)
		(layer "In6.Cu")
		(net "DMI_CPU0_PCH_TX_DN<5>")
	)
	(segment
		(start 368.696494 -223.899476)
		(end 368.704368 -223.894904)
		(width 0.0889)
		(layer "In6.Cu")
		(net "DMI_CPU0_PCH_TX_DN<5>")
	)
	(segment
		(start 349.668338 -69.490336)
		(end 348.30512 -68.127118)
		(width 0.14732)
		(layer "In6.Cu")
		(net "DMI_CPU0_PCH_TX_DN<5>")
	)
	(segment
		(start 370.105432 -219.830396)
		(end 370.114322 -219.825316)
		(width 0.0889)
		(layer "In6.Cu")
		(net "DMI_CPU0_PCH_TX_DN<5>")
	)
	(segment
		(start 352.55581 -79.82712)
		(end 350.793558 -72.208136)
		(width 0.14732)
		(layer "In6.Cu")
		(net "DMI_CPU0_PCH_TX_DN<5>")
	)
	(segment
		(start 388.647178 -190.747904)
		(end 390.71931 -178.997864)
		(width 0.14732)
		(layer "In6.Cu")
		(net "DMI_CPU0_PCH_TX_DN<5>")
	)
	(segment
		(start 372.631716 -213.698074)
		(end 372.532656 -213.599014)
		(width 0.0889)
		(layer "In6.Cu")
		(net "DMI_CPU0_PCH_TX_DN<5>")
	)
	(segment
		(start 370.099336 -221.461838)
		(end 370.102638 -221.459806)
		(width 0.0889)
		(layer "In6.Cu")
		(net "DMI_CPU0_PCH_TX_DN<5>")
	)
	(segment
		(start 365.023146 -227.964238)
		(end 365.032036 -227.969318)
		(width 0.0889)
		(layer "In6.Cu")
		(net "DMI_CPU0_PCH_TX_DN<5>")
	)
	(segment
		(start 371.039136 -218.20632)
		(end 371.05209 -218.198954)
		(width 0.0889)
		(layer "In6.Cu")
		(net "DMI_CPU0_PCH_TX_DN<5>")
	)
	(segment
		(start 372.589806 -212.209634)
		(end 372.589806 -212.187536)
		(width 0.0889)
		(layer "In6.Cu")
		(net "DMI_CPU0_PCH_TX_DN<5>")
	)
	(arc
		(start 371.054122 -218.197684)
		(mid 371.232719 -217.878406)
		(end 371.054122 -217.559128)
		(width 0.0889)
		(layer "In6.Cu")
		(net "DMI_CPU0_PCH_TX_DN<5>")
	)
	(arc
		(start 370.105432 -220.809566)
		(mid 369.901951 -220.608762)
		(end 369.82273 -220.334078)
		(width 0.0889)
		(layer "In6.Cu")
		(net "DMI_CPU0_PCH_TX_DN<5>")
	)
	(arc
		(start 368.704368 -223.894904)
		(mid 368.835282 -223.758544)
		(end 368.88293 -223.575626)
		(width 0.0889)
		(layer "In6.Cu")
		(net "DMI_CPU0_PCH_TX_DN<5>")
	)
	(arc
		(start 365.31423 -228.45903)
		(mid 365.68888 -228.83368)
		(end 366.06353 -228.45903)
		(width 0.0889)
		(layer "In6.Cu")
		(net "DMI_CPU0_PCH_TX_DN<5>")
	)
	(arc
		(start 371.515132 -215.761062)
		(mid 371.650065 -215.627708)
		(end 371.70233 -215.44534)
		(width 0.0889)
		(layer "In6.Cu")
		(net "DMI_CPU0_PCH_TX_DN<5>")
	)
	(arc
		(start 364.844584 -227.64496)
		(mid 364.844636 -227.652327)
		(end 364.844838 -227.659692)
		(width 0.0889)
		(layer "In6.Cu")
		(net "DMI_CPU0_PCH_TX_DN<5>")
	)
	(arc
		(start 370.292884 -219.490544)
		(mid 370.372254 -219.21681)
		(end 370.575078 -219.01658)
		(width 0.0889)
		(layer "In6.Cu")
		(net "DMI_CPU0_PCH_TX_DN<5>")
	)
	(arc
		(start 368.695478 -224.8789)
		(mid 368.492655 -224.678669)
		(end 368.413284 -224.404936)
		(width 0.0889)
		(layer "In6.Cu")
		(net "DMI_CPU0_PCH_TX_DN<5>")
	)
	(arc
		(start 371.70233 -215.436704)
		(mid 371.776321 -215.157138)
		(end 371.978936 -214.950802)
		(width 0.0889)
		(layer "In6.Cu")
		(net "DMI_CPU0_PCH_TX_DN<5>")
	)
	(arc
		(start 371.232684 -216.240614)
		(mid 371.310795 -215.963665)
		(end 371.515132 -215.761062)
		(width 0.0889)
		(layer "In6.Cu")
		(net "DMI_CPU0_PCH_TX_DN<5>")
	)
	(arc
		(start 370.76253 -218.692222)
		(mid 370.836521 -218.412656)
		(end 371.039136 -218.20632)
		(width 0.0889)
		(layer "In6.Cu")
		(net "DMI_CPU0_PCH_TX_DN<5>")
	)
	(arc
		(start 369.174522 -223.080834)
		(mid 369.305436 -222.944474)
		(end 369.353084 -222.761556)
		(width 0.0889)
		(layer "In6.Cu")
		(net "DMI_CPU0_PCH_TX_DN<5>")
	)
	(arc
		(start 371.045232 -217.554048)
		(mid 370.762398 -217.071459)
		(end 371.03304 -216.58199)
		(width 0.0889)
		(layer "In6.Cu")
		(net "DMI_CPU0_PCH_TX_DN<5>")
	)
	(arc
		(start 370.583968 -219.0115)
		(mid 370.714882 -218.87514)
		(end 370.76253 -218.692222)
		(width 0.0889)
		(layer "In6.Cu")
		(net "DMI_CPU0_PCH_TX_DN<5>")
	)
	(arc
		(start 368.413284 -225.99523)
		(mid 368.494195 -225.725102)
		(end 368.695478 -225.527616)
		(width 0.0889)
		(layer "In6.Cu")
		(net "DMI_CPU0_PCH_TX_DN<5>")
	)
	(arc
		(start 370.114322 -219.825316)
		(mid 370.245236 -219.688956)
		(end 370.292884 -219.506038)
		(width 0.0889)
		(layer "In6.Cu")
		(net "DMI_CPU0_PCH_TX_DN<5>")
	)
	(arc
		(start 369.82273 -221.94774)
		(mid 369.896721 -221.668174)
		(end 370.099336 -221.461838)
		(width 0.0889)
		(layer "In6.Cu")
		(net "DMI_CPU0_PCH_TX_DN<5>")
	)
	(arc
		(start 367.94313 -226.831144)
		(mid 368.017121 -226.551578)
		(end 368.219736 -226.345242)
		(width 0.0889)
		(layer "In6.Cu")
		(net "DMI_CPU0_PCH_TX_DN<5>")
	)
	(arc
		(start 368.704368 -225.522536)
		(mid 368.831622 -225.39257)
		(end 368.882676 -225.21799)
		(width 0.0889)
		(layer "In6.Cu")
		(net "DMI_CPU0_PCH_TX_DN<5>")
	)
	(arc
		(start 368.413284 -224.373948)
		(mid 368.492654 -224.100214)
		(end 368.695478 -223.899984)
		(width 0.0889)
		(layer "In6.Cu")
		(net "DMI_CPU0_PCH_TX_DN<5>")
	)
	(arc
		(start 371.054122 -216.569798)
		(mid 371.185036 -216.433438)
		(end 371.232684 -216.25052)
		(width 0.0889)
		(layer "In6.Cu")
		(net "DMI_CPU0_PCH_TX_DN<5>")
	)
	(arc
		(start 364.633764 -227.204524)
		(mid 364.789162 -227.400805)
		(end 364.844584 -227.64496)
		(width 0.0889)
		(layer "In6.Cu")
		(net "DMI_CPU0_PCH_TX_DN<5>")
	)
	(arc
		(start 369.353084 -222.746062)
		(mid 369.432454 -222.472328)
		(end 369.635278 -222.272098)
		(width 0.0889)
		(layer "In6.Cu")
		(net "DMI_CPU0_PCH_TX_DN<5>")
	)
	(arc
		(start 368.88293 -223.568006)
		(mid 368.960559 -223.289593)
		(end 369.165632 -223.085914)
		(width 0.0889)
		(layer "In6.Cu")
		(net "DMI_CPU0_PCH_TX_DN<5>")
	)
	(arc
		(start 370.114322 -221.453202)
		(mid 370.292919 -221.133924)
		(end 370.114322 -220.814646)
		(width 0.0889)
		(layer "In6.Cu")
		(net "DMI_CPU0_PCH_TX_DN<5>")
	)
	(arc
		(start 368.234722 -226.336606)
		(mid 368.365636 -226.200246)
		(end 368.413284 -226.017328)
		(width 0.0889)
		(layer "In6.Cu")
		(net "DMI_CPU0_PCH_TX_DN<5>")
	)
	(arc
		(start 369.644168 -222.267018)
		(mid 369.775082 -222.130658)
		(end 369.82273 -221.94774)
		(width 0.0889)
		(layer "In6.Cu")
		(net "DMI_CPU0_PCH_TX_DN<5>")
	)
	(arc
		(start 364.844838 -227.659692)
		(mid 364.895892 -227.834272)
		(end 365.023146 -227.964238)
		(width 0.0889)
		(layer "In6.Cu")
		(net "DMI_CPU0_PCH_TX_DN<5>")
	)
	(arc
		(start 364.616746 -227.191316)
		(mid 364.625318 -227.197838)
		(end 364.633764 -227.204524)
		(width 0.0889)
		(layer "In6.Cu")
		(net "DMI_CPU0_PCH_TX_DN<5>")
	)
	(arc
		(start 365.032036 -227.969318)
		(mid 365.233318 -228.166805)
		(end 365.31423 -228.436932)
		(width 0.0889)
		(layer "In6.Cu")
		(net "DMI_CPU0_PCH_TX_DN<5>")
	)
	(arc
		(start 366.911636 -227.969318)
		(mid 367.286111 -227.969272)
		(end 367.473484 -227.64496)
		(width 0.0889)
		(layer "In6.Cu")
		(net "DMI_CPU0_PCH_TX_DN<5>")
	)
	(arc
		(start 368.88293 -225.193098)
		(mid 368.832861 -225.015873)
		(end 368.704368 -224.88398)
		(width 0.0889)
		(layer "In6.Cu")
		(net "DMI_CPU0_PCH_TX_DN<5>")
	)
	(arc
		(start 371.985032 -214.947246)
		(mid 372.025845 -214.919943)
		(end 372.062756 -214.887556)
		(width 0.0889)
		(layer "In6.Cu")
		(net "DMI_CPU0_PCH_TX_DN<5>")
	)
	(arc
		(start 367.473484 -227.635054)
		(mid 367.551595 -227.358105)
		(end 367.755932 -227.155502)
		(width 0.0889)
		(layer "In6.Cu")
		(net "DMI_CPU0_PCH_TX_DN<5>")
	)
	(arc
		(start 369.82273 -220.319854)
		(mid 369.896721 -220.040288)
		(end 370.099336 -219.833952)
		(width 0.0889)
		(layer "In6.Cu")
		(net "DMI_CPU0_PCH_TX_DN<5>")
	)
	(arc
		(start 368.882676 -225.21799)
		(mid 368.883009 -225.205546)
		(end 368.88293 -225.193098)
		(width 0.0889)
		(layer "In6.Cu")
		(net "DMI_CPU0_PCH_TX_DN<5>")
	)
	(arc
		(start 366.06353 -228.444806)
		(mid 366.352312 -227.96571)
		(end 366.911636 -227.969318)
		(width 0.0889)
		(layer "In6.Cu")
		(net "DMI_CPU0_PCH_TX_DN<5>")
	)
	(arc
		(start 367.755932 -227.155502)
		(mid 367.890865 -227.022148)
		(end 367.94313 -226.83978)
		(width 0.0889)
		(layer "In6.Cu")
		(net "DMI_CPU0_PCH_TX_DN<5>")
	)
	(segment
		(start 363.33938 -228.1809)
		(end 363.339634 -228.180646)
		(width 0.13208)
		(layer "F.Cu")
		(net "DMI_CPU0_PCH_TX_DN<4>")
	)
	(segment
		(start 349.228664 -66.074544)
		(end 349.570548 -66.400934)
		(width 0.13208)
		(layer "F.Cu")
		(net "DMI_CPU0_PCH_TX_DN<4>")
	)
	(segment
		(start 349.570548 -66.400934)
		(end 349.573088 -66.403474)
		(width 0.13208)
		(layer "F.Cu")
		(net "DMI_CPU0_PCH_TX_DN<4>")
	)
	(segment
		(start 363.339634 -228.180646)
		(end 363.339634 -227.64496)
		(width 0.13208)
		(layer "F.Cu")
		(net "DMI_CPU0_PCH_TX_DN<4>")
	)
	(segment
		(start 349.573088 -66.403474)
		(end 350.349058 -66.403474)
		(width 0.13208)
		(layer "F.Cu")
		(net "DMI_CPU0_PCH_TX_DN<4>")
	)
	(segment
		(start 350.349058 -66.403474)
		(end 350.652588 -66.099944)
		(width 0.13208)
		(layer "F.Cu")
		(net "DMI_CPU0_PCH_TX_DN<4>")
	)
	(segment
		(start 363.496098 -227.915978)
		(end 363.584998 -227.9396)
		(width 0.0889)
		(layer "In6.Cu")
		(net "DMI_CPU0_PCH_TX_DN<4>")
	)
	(segment
		(start 367.94313 -228.45903)
		(end 367.94313 -228.444806)
		(width 0.0889)
		(layer "In6.Cu")
		(net "DMI_CPU0_PCH_TX_DN<4>")
	)
	(segment
		(start 372.172484 -216.25052)
		(end 372.172484 -216.235026)
		(width 0.0889)
		(layer "In6.Cu")
		(net "DMI_CPU0_PCH_TX_DN<4>")
	)
	(segment
		(start 388.581646 -161.884106)
		(end 385.567936 -144.792446)
		(width 0.14732)
		(layer "In6.Cu")
		(net "DMI_CPU0_PCH_TX_DN<4>")
	)
	(segment
		(start 373.523764 -212.396324)
		(end 373.622824 -212.297264)
		(width 0.0889)
		(layer "In6.Cu")
		(net "DMI_CPU0_PCH_TX_DN<4>")
	)
	(segment
		(start 368.695478 -227.155502)
		(end 368.696494 -227.154994)
		(width 0.0889)
		(layer "In6.Cu")
		(net "DMI_CPU0_PCH_TX_DN<4>")
	)
	(segment
		(start 349.479616 -66.394584)
		(end 350.357948 -66.394584)
		(width 0.14732)
		(layer "In6.Cu")
		(net "DMI_CPU0_PCH_TX_DN<4>")
	)
	(segment
		(start 373.580914 -210.914488)
		(end 373.58066 -210.914742)
		(width 0.14732)
		(layer "In6.Cu")
		(net "DMI_CPU0_PCH_TX_DN<4>")
	)
	(segment
		(start 369.353084 -226.017328)
		(end 369.353084 -225.99523)
		(width 0.0889)
		(layer "In6.Cu")
		(net "DMI_CPU0_PCH_TX_DN<4>")
	)
	(segment
		(start 373.622824 -212.759544)
		(end 373.523764 -212.660484)
		(width 0.0889)
		(layer "In6.Cu")
		(net "DMI_CPU0_PCH_TX_DN<4>")
	)
	(segment
		(start 373.58066 -209.746088)
		(end 373.759476 -208.726786)
		(width 0.14732)
		(layer "In6.Cu")
		(net "DMI_CPU0_PCH_TX_DN<4>")
	)
	(segment
		(start 370.292884 -222.761556)
		(end 370.292884 -222.746062)
		(width 0.0889)
		(layer "In6.Cu")
		(net "DMI_CPU0_PCH_TX_DN<4>")
	)
	(segment
		(start 364.562644 -228.783896)
		(end 364.567978 -228.786944)
		(width 0.0889)
		(layer "In6.Cu")
		(net "DMI_CPU0_PCH_TX_DN<4>")
	)
	(segment
		(start 389.421878 -191.301116)
		(end 391.59561 -178.976274)
		(width 0.14732)
		(layer "In6.Cu")
		(net "DMI_CPU0_PCH_TX_DN<4>")
	)
	(segment
		(start 353.609402 -79.963518)
		(end 351.68713 -71.718678)
		(width 0.14732)
		(layer "In6.Cu")
		(net "DMI_CPU0_PCH_TX_DN<4>")
	)
	(segment
		(start 377.769628 -202.99934)
		(end 384.560064 -198.24446)
		(width 0.14732)
		(layer "In6.Cu")
		(net "DMI_CPU0_PCH_TX_DN<4>")
	)
	(segment
		(start 373.622824 -214.26678)
		(end 373.622824 -213.485984)
		(width 0.0889)
		(layer "In6.Cu")
		(net "DMI_CPU0_PCH_TX_DN<4>")
	)
	(segment
		(start 373.622824 -212.297264)
		(end 373.622824 -212.033104)
		(width 0.0889)
		(layer "In6.Cu")
		(net "DMI_CPU0_PCH_TX_DN<4>")
	)
	(segment
		(start 350.684592 -69.29755)
		(end 349.151448 -67.764406)
		(width 0.14732)
		(layer "In6.Cu")
		(net "DMI_CPU0_PCH_TX_DN<4>")
	)
	(segment
		(start 368.225832 -227.969318)
		(end 368.234722 -227.964238)
		(width 0.0889)
		(layer "In6.Cu")
		(net "DMI_CPU0_PCH_TX_DN<4>")
	)
	(segment
		(start 371.05209 -221.454472)
		(end 371.054122 -221.453202)
		(width 0.0889)
		(layer "In6.Cu")
		(net "DMI_CPU0_PCH_TX_DN<4>")
	)
	(segment
		(start 368.696494 -227.154994)
		(end 368.704368 -227.150422)
		(width 0.0889)
		(layer "In6.Cu")
		(net "DMI_CPU0_PCH_TX_DN<4>")
	)
	(segment
		(start 369.635278 -225.527616)
		(end 369.644168 -225.522536)
		(width 0.0889)
		(layer "In6.Cu")
		(net "DMI_CPU0_PCH_TX_DN<4>")
	)
	(segment
		(start 364.561882 -228.783388)
		(end 364.562644 -228.783896)
		(width 0.0889)
		(layer "In6.Cu")
		(net "DMI_CPU0_PCH_TX_DN<4>")
	)
	(segment
		(start 363.339634 -227.64496)
		(end 363.496098 -227.915978)
		(width 0.0889)
		(layer "In6.Cu")
		(net "DMI_CPU0_PCH_TX_DN<4>")
	)
	(segment
		(start 384.560064 -198.24446)
		(end 389.421878 -191.301116)
		(width 0.14732)
		(layer "In6.Cu")
		(net "DMI_CPU0_PCH_TX_DN<4>")
	)
	(segment
		(start 372.454678 -215.761062)
		(end 372.463568 -215.755982)
		(width 0.0889)
		(layer "In6.Cu")
		(net "DMI_CPU0_PCH_TX_DN<4>")
	)
	(segment
		(start 371.232684 -219.506038)
		(end 371.232684 -219.490544)
		(width 0.0889)
		(layer "In6.Cu")
		(net "DMI_CPU0_PCH_TX_DN<4>")
	)
	(segment
		(start 373.622824 -213.023704)
		(end 373.622824 -212.759544)
		(width 0.0889)
		(layer "In6.Cu")
		(net "DMI_CPU0_PCH_TX_DN<4>")
	)
	(segment
		(start 371.70233 -217.07856)
		(end 371.70233 -217.064336)
		(width 0.0889)
		(layer "In6.Cu")
		(net "DMI_CPU0_PCH_TX_DN<4>")
	)
	(segment
		(start 349.151448 -67.764406)
		(end 349.151448 -66.722752)
		(width 0.14732)
		(layer "In6.Cu")
		(net "DMI_CPU0_PCH_TX_DN<4>")
	)
	(segment
		(start 365.406432 -229.597204)
		(end 365.421164 -229.588568)
		(width 0.0889)
		(layer "In6.Cu")
		(net "DMI_CPU0_PCH_TX_DN<4>")
	)
	(segment
		(start 373.001794 -214.88781)
		(end 373.622824 -214.26678)
		(width 0.0889)
		(layer "In6.Cu")
		(net "DMI_CPU0_PCH_TX_DN<4>")
	)
	(segment
		(start 371.99189 -218.198954)
		(end 371.993922 -218.197684)
		(width 0.0889)
		(layer "In6.Cu")
		(net "DMI_CPU0_PCH_TX_DN<4>")
	)
	(segment
		(start 351.68713 -71.718678)
		(end 350.684592 -69.29755)
		(width 0.14732)
		(layer "In6.Cu")
		(net "DMI_CPU0_PCH_TX_DN<4>")
	)
	(segment
		(start 368.413284 -227.64496)
		(end 368.413284 -227.629466)
		(width 0.0889)
		(layer "In6.Cu")
		(net "DMI_CPU0_PCH_TX_DN<4>")
	)
	(segment
		(start 371.039136 -221.461838)
		(end 371.05209 -221.454472)
		(width 0.0889)
		(layer "In6.Cu")
		(net "DMI_CPU0_PCH_TX_DN<4>")
	)
	(segment
		(start 349.151448 -66.722752)
		(end 349.479616 -66.394584)
		(width 0.14732)
		(layer "In6.Cu")
		(net "DMI_CPU0_PCH_TX_DN<4>")
	)
	(segment
		(start 364.552992 -228.778308)
		(end 364.560358 -228.782626)
		(width 0.0889)
		(layer "In6.Cu")
		(net "DMI_CPU0_PCH_TX_DN<4>")
	)
	(segment
		(start 371.054122 -220.814646)
		(end 371.045994 -220.810074)
		(width 0.0889)
		(layer "In6.Cu")
		(net "DMI_CPU0_PCH_TX_DN<4>")
	)
	(segment
		(start 369.82273 -223.584262)
		(end 369.82273 -223.561402)
		(width 0.0889)
		(layer "In6.Cu")
		(net "DMI_CPU0_PCH_TX_DN<4>")
	)
	(segment
		(start 373.523764 -211.934044)
		(end 373.523764 -211.669884)
		(width 0.0889)
		(layer "In6.Cu")
		(net "DMI_CPU0_PCH_TX_DN<4>")
	)
	(segment
		(start 366.533684 -229.272846)
		(end 366.533684 -229.257352)
		(width 0.0889)
		(layer "In6.Cu")
		(net "DMI_CPU0_PCH_TX_DN<4>")
	)
	(segment
		(start 373.580914 -211.272628)
		(end 373.580914 -211.25053)
		(width 0.0889)
		(layer "In6.Cu")
		(net "DMI_CPU0_PCH_TX_DN<4>")
	)
	(segment
		(start 388.581646 -161.88436)
		(end 388.581646 -161.884106)
		(width 0.14732)
		(layer "In6.Cu")
		(net "DMI_CPU0_PCH_TX_DN<4>")
	)
	(segment
		(start 370.105432 -223.085914)
		(end 370.114322 -223.080834)
		(width 0.0889)
		(layer "In6.Cu")
		(net "DMI_CPU0_PCH_TX_DN<4>")
	)
	(segment
		(start 364.37443 -228.436932)
		(end 364.37443 -228.45903)
		(width 0.0889)
		(layer "In6.Cu")
		(net "DMI_CPU0_PCH_TX_DN<4>")
	)
	(segment
		(start 373.580914 -211.25053)
		(end 373.580914 -210.914488)
		(width 0.14732)
		(layer "In6.Cu")
		(net "DMI_CPU0_PCH_TX_DN<4>")
	)
	(segment
		(start 373.523764 -212.660484)
		(end 373.523764 -212.396324)
		(width 0.0889)
		(layer "In6.Cu")
		(net "DMI_CPU0_PCH_TX_DN<4>")
	)
	(segment
		(start 371.993922 -217.559128)
		(end 371.985032 -217.554048)
		(width 0.0889)
		(layer "In6.Cu")
		(net "DMI_CPU0_PCH_TX_DN<4>")
	)
	(segment
		(start 373.622824 -211.570824)
		(end 373.622824 -211.314538)
		(width 0.0889)
		(layer "In6.Cu")
		(net "DMI_CPU0_PCH_TX_DN<4>")
	)
	(segment
		(start 391.59561 -178.976274)
		(end 388.581646 -161.88436)
		(width 0.14732)
		(layer "In6.Cu")
		(net "DMI_CPU0_PCH_TX_DN<4>")
	)
	(segment
		(start 373.622824 -212.033104)
		(end 373.523764 -211.934044)
		(width 0.0889)
		(layer "In6.Cu")
		(net "DMI_CPU0_PCH_TX_DN<4>")
	)
	(segment
		(start 373.58066 -210.914742)
		(end 373.58066 -209.746088)
		(width 0.14732)
		(layer "In6.Cu")
		(net "DMI_CPU0_PCH_TX_DN<4>")
	)
	(segment
		(start 371.045994 -220.810074)
		(end 371.045232 -220.809566)
		(width 0.0889)
		(layer "In6.Cu")
		(net "DMI_CPU0_PCH_TX_DN<4>")
	)
	(segment
		(start 373.523764 -211.669884)
		(end 373.622824 -211.570824)
		(width 0.0889)
		(layer "In6.Cu")
		(net "DMI_CPU0_PCH_TX_DN<4>")
	)
	(segment
		(start 371.514878 -219.01658)
		(end 371.523768 -219.0115)
		(width 0.0889)
		(layer "In6.Cu")
		(net "DMI_CPU0_PCH_TX_DN<4>")
	)
	(segment
		(start 367.36655 -228.774752)
		(end 367.381282 -228.783388)
		(width 0.0889)
		(layer "In6.Cu")
		(net "DMI_CPU0_PCH_TX_DN<4>")
	)
	(segment
		(start 373.759476 -208.726786)
		(end 377.769628 -202.99934)
		(width 0.14732)
		(layer "In6.Cu")
		(net "DMI_CPU0_PCH_TX_DN<4>")
	)
	(segment
		(start 369.644168 -224.88398)
		(end 369.635278 -224.8789)
		(width 0.0889)
		(layer "In6.Cu")
		(net "DMI_CPU0_PCH_TX_DN<4>")
	)
	(segment
		(start 371.03304 -219.837508)
		(end 371.054122 -219.825316)
		(width 0.0889)
		(layer "In6.Cu")
		(net "DMI_CPU0_PCH_TX_DN<4>")
	)
	(segment
		(start 371.978936 -216.578434)
		(end 371.993922 -216.569798)
		(width 0.0889)
		(layer "In6.Cu")
		(net "DMI_CPU0_PCH_TX_DN<4>")
	)
	(segment
		(start 373.523764 -213.386924)
		(end 373.523764 -213.122764)
		(width 0.0889)
		(layer "In6.Cu")
		(net "DMI_CPU0_PCH_TX_DN<4>")
	)
	(segment
		(start 373.622824 -211.314538)
		(end 373.580914 -211.272628)
		(width 0.0889)
		(layer "In6.Cu")
		(net "DMI_CPU0_PCH_TX_DN<4>")
	)
	(segment
		(start 385.567936 -144.792446)
		(end 353.609402 -79.963518)
		(width 0.14732)
		(layer "In6.Cu")
		(net "DMI_CPU0_PCH_TX_DN<4>")
	)
	(segment
		(start 350.357948 -66.394584)
		(end 350.652588 -66.099944)
		(width 0.14732)
		(layer "In6.Cu")
		(net "DMI_CPU0_PCH_TX_DN<4>")
	)
	(segment
		(start 364.560358 -228.782626)
		(end 364.561882 -228.783388)
		(width 0.0889)
		(layer "In6.Cu")
		(net "DMI_CPU0_PCH_TX_DN<4>")
	)
	(segment
		(start 372.64213 -215.436704)
		(end 372.64213 -215.42121)
		(width 0.0889)
		(layer "In6.Cu")
		(net "DMI_CPU0_PCH_TX_DN<4>")
	)
	(segment
		(start 370.575078 -222.272098)
		(end 370.583968 -222.267018)
		(width 0.0889)
		(layer "In6.Cu")
		(net "DMI_CPU0_PCH_TX_DN<4>")
	)
	(segment
		(start 371.978936 -218.20632)
		(end 371.99189 -218.198954)
		(width 0.0889)
		(layer "In6.Cu")
		(net "DMI_CPU0_PCH_TX_DN<4>")
	)
	(segment
		(start 373.523764 -213.122764)
		(end 373.622824 -213.023704)
		(width 0.0889)
		(layer "In6.Cu")
		(net "DMI_CPU0_PCH_TX_DN<4>")
	)
	(segment
		(start 373.622824 -213.485984)
		(end 373.523764 -213.386924)
		(width 0.0889)
		(layer "In6.Cu")
		(net "DMI_CPU0_PCH_TX_DN<4>")
	)
	(segment
		(start 369.15344 -226.348798)
		(end 369.174522 -226.336606)
		(width 0.0889)
		(layer "In6.Cu")
		(net "DMI_CPU0_PCH_TX_DN<4>")
	)
	(arc
		(start 369.82273 -225.193098)
		(mid 369.772661 -225.015873)
		(end 369.644168 -224.88398)
		(width 0.0889)
		(layer "In6.Cu")
		(net "DMI_CPU0_PCH_TX_DN<4>")
	)
	(arc
		(start 372.64213 -215.42121)
		(mid 372.7215 -215.147476)
		(end 372.924324 -214.947246)
		(width 0.0889)
		(layer "In6.Cu")
		(net "DMI_CPU0_PCH_TX_DN<4>")
	)
	(arc
		(start 369.635278 -224.8789)
		(mid 369.352873 -224.389332)
		(end 369.635532 -223.899984)
		(width 0.0889)
		(layer "In6.Cu")
		(net "DMI_CPU0_PCH_TX_DN<4>")
	)
	(arc
		(start 370.114322 -223.080834)
		(mid 370.245236 -222.944474)
		(end 370.292884 -222.761556)
		(width 0.0889)
		(layer "In6.Cu")
		(net "DMI_CPU0_PCH_TX_DN<4>")
	)
	(arc
		(start 368.88293 -226.831144)
		(mid 368.955165 -226.55462)
		(end 369.15344 -226.348798)
		(width 0.0889)
		(layer "In6.Cu")
		(net "DMI_CPU0_PCH_TX_DN<4>")
	)
	(arc
		(start 369.82273 -223.561402)
		(mid 369.901949 -223.286717)
		(end 370.105432 -223.085914)
		(width 0.0889)
		(layer "In6.Cu")
		(net "DMI_CPU0_PCH_TX_DN<4>")
	)
	(arc
		(start 370.583968 -222.267018)
		(mid 370.714882 -222.130658)
		(end 370.76253 -221.94774)
		(width 0.0889)
		(layer "In6.Cu")
		(net "DMI_CPU0_PCH_TX_DN<4>")
	)
	(arc
		(start 366.533684 -229.257352)
		(mid 366.815416 -228.783654)
		(end 367.36655 -228.774752)
		(width 0.0889)
		(layer "In6.Cu")
		(net "DMI_CPU0_PCH_TX_DN<4>")
	)
	(arc
		(start 367.381282 -228.783388)
		(mid 367.755757 -228.783342)
		(end 367.94313 -228.45903)
		(width 0.0889)
		(layer "In6.Cu")
		(net "DMI_CPU0_PCH_TX_DN<4>")
	)
	(arc
		(start 371.523768 -219.0115)
		(mid 371.654682 -218.87514)
		(end 371.70233 -218.692222)
		(width 0.0889)
		(layer "In6.Cu")
		(net "DMI_CPU0_PCH_TX_DN<4>")
	)
	(arc
		(start 371.70233 -217.064336)
		(mid 371.776321 -216.78477)
		(end 371.978936 -216.578434)
		(width 0.0889)
		(layer "In6.Cu")
		(net "DMI_CPU0_PCH_TX_DN<4>")
	)
	(arc
		(start 372.463568 -215.755982)
		(mid 372.594482 -215.619622)
		(end 372.64213 -215.436704)
		(width 0.0889)
		(layer "In6.Cu")
		(net "DMI_CPU0_PCH_TX_DN<4>")
	)
	(arc
		(start 370.76253 -221.94774)
		(mid 370.836521 -221.668174)
		(end 371.039136 -221.461838)
		(width 0.0889)
		(layer "In6.Cu")
		(net "DMI_CPU0_PCH_TX_DN<4>")
	)
	(arc
		(start 371.993922 -216.569798)
		(mid 372.124836 -216.433438)
		(end 372.172484 -216.25052)
		(width 0.0889)
		(layer "In6.Cu")
		(net "DMI_CPU0_PCH_TX_DN<4>")
	)
	(arc
		(start 368.704368 -227.150422)
		(mid 368.835282 -227.014062)
		(end 368.88293 -226.831144)
		(width 0.0889)
		(layer "In6.Cu")
		(net "DMI_CPU0_PCH_TX_DN<4>")
	)
	(arc
		(start 364.844584 -229.272846)
		(mid 365.031883 -229.597287)
		(end 365.406432 -229.597204)
		(width 0.0889)
		(layer "In6.Cu")
		(net "DMI_CPU0_PCH_TX_DN<4>")
	)
	(arc
		(start 369.353084 -225.99523)
		(mid 369.433995 -225.725102)
		(end 369.635278 -225.527616)
		(width 0.0889)
		(layer "In6.Cu")
		(net "DMI_CPU0_PCH_TX_DN<4>")
	)
	(arc
		(start 371.232684 -219.490544)
		(mid 371.312054 -219.21681)
		(end 371.514878 -219.01658)
		(width 0.0889)
		(layer "In6.Cu")
		(net "DMI_CPU0_PCH_TX_DN<4>")
	)
	(arc
		(start 367.94313 -228.444806)
		(mid 368.022349 -228.170121)
		(end 368.225832 -227.969318)
		(width 0.0889)
		(layer "In6.Cu")
		(net "DMI_CPU0_PCH_TX_DN<4>")
	)
	(arc
		(start 363.584998 -227.9396)
		(mid 363.594866 -227.935443)
		(end 363.60481 -227.931472)
		(width 0.0889)
		(layer "In6.Cu")
		(net "DMI_CPU0_PCH_TX_DN<4>")
	)
	(arc
		(start 370.292884 -222.746062)
		(mid 370.372254 -222.472328)
		(end 370.575078 -222.272098)
		(width 0.0889)
		(layer "In6.Cu")
		(net "DMI_CPU0_PCH_TX_DN<4>")
	)
	(arc
		(start 371.70233 -218.692222)
		(mid 371.776321 -218.412656)
		(end 371.978936 -218.20632)
		(width 0.0889)
		(layer "In6.Cu")
		(net "DMI_CPU0_PCH_TX_DN<4>")
	)
	(arc
		(start 369.644168 -225.522536)
		(mid 369.771422 -225.39257)
		(end 369.822476 -225.21799)
		(width 0.0889)
		(layer "In6.Cu")
		(net "DMI_CPU0_PCH_TX_DN<4>")
	)
	(arc
		(start 364.37443 -228.45903)
		(mid 364.422109 -228.64193)
		(end 364.552992 -228.778308)
		(width 0.0889)
		(layer "In6.Cu")
		(net "DMI_CPU0_PCH_TX_DN<4>")
	)
	(arc
		(start 368.413284 -227.629466)
		(mid 368.492654 -227.355732)
		(end 368.695478 -227.155502)
		(width 0.0889)
		(layer "In6.Cu")
		(net "DMI_CPU0_PCH_TX_DN<4>")
	)
	(arc
		(start 364.567978 -228.786944)
		(mid 364.770565 -228.993295)
		(end 364.844584 -229.272846)
		(width 0.0889)
		(layer "In6.Cu")
		(net "DMI_CPU0_PCH_TX_DN<4>")
	)
	(arc
		(start 371.054122 -219.825316)
		(mid 371.185036 -219.688956)
		(end 371.232684 -219.506038)
		(width 0.0889)
		(layer "In6.Cu")
		(net "DMI_CPU0_PCH_TX_DN<4>")
	)
	(arc
		(start 372.172484 -216.235026)
		(mid 372.251854 -215.961292)
		(end 372.454678 -215.761062)
		(width 0.0889)
		(layer "In6.Cu")
		(net "DMI_CPU0_PCH_TX_DN<4>")
	)
	(arc
		(start 372.924324 -214.947246)
		(mid 372.964994 -214.920052)
		(end 373.001794 -214.88781)
		(width 0.0889)
		(layer "In6.Cu")
		(net "DMI_CPU0_PCH_TX_DN<4>")
	)
	(arc
		(start 369.174522 -226.336606)
		(mid 369.305436 -226.200246)
		(end 369.353084 -226.017328)
		(width 0.0889)
		(layer "In6.Cu")
		(net "DMI_CPU0_PCH_TX_DN<4>")
	)
	(arc
		(start 365.421164 -229.588568)
		(mid 365.697639 -229.521248)
		(end 365.971836 -229.597204)
		(width 0.0889)
		(layer "In6.Cu")
		(net "DMI_CPU0_PCH_TX_DN<4>")
	)
	(arc
		(start 369.822476 -225.21799)
		(mid 369.822809 -225.205546)
		(end 369.82273 -225.193098)
		(width 0.0889)
		(layer "In6.Cu")
		(net "DMI_CPU0_PCH_TX_DN<4>")
	)
	(arc
		(start 369.635532 -223.899984)
		(mid 369.770465 -223.76663)
		(end 369.82273 -223.584262)
		(width 0.0889)
		(layer "In6.Cu")
		(net "DMI_CPU0_PCH_TX_DN<4>")
	)
	(arc
		(start 363.60481 -227.931472)
		(mid 364.119814 -227.986067)
		(end 364.37443 -228.436932)
		(width 0.0889)
		(layer "In6.Cu")
		(net "DMI_CPU0_PCH_TX_DN<4>")
	)
	(arc
		(start 371.054122 -221.453202)
		(mid 371.232719 -221.133924)
		(end 371.054122 -220.814646)
		(width 0.0889)
		(layer "In6.Cu")
		(net "DMI_CPU0_PCH_TX_DN<4>")
	)
	(arc
		(start 371.985032 -217.554048)
		(mid 371.781551 -217.353244)
		(end 371.70233 -217.07856)
		(width 0.0889)
		(layer "In6.Cu")
		(net "DMI_CPU0_PCH_TX_DN<4>")
	)
	(arc
		(start 371.045232 -220.809566)
		(mid 370.762398 -220.326977)
		(end 371.03304 -219.837508)
		(width 0.0889)
		(layer "In6.Cu")
		(net "DMI_CPU0_PCH_TX_DN<4>")
	)
	(arc
		(start 365.971836 -229.597204)
		(mid 366.346311 -229.597158)
		(end 366.533684 -229.272846)
		(width 0.0889)
		(layer "In6.Cu")
		(net "DMI_CPU0_PCH_TX_DN<4>")
	)
	(arc
		(start 371.993922 -218.197684)
		(mid 372.172519 -217.878406)
		(end 371.993922 -217.559128)
		(width 0.0889)
		(layer "In6.Cu")
		(net "DMI_CPU0_PCH_TX_DN<4>")
	)
	(arc
		(start 368.234722 -227.964238)
		(mid 368.365636 -227.827878)
		(end 368.413284 -227.64496)
		(width 0.0889)
		(layer "In6.Cu")
		(net "DMI_CPU0_PCH_TX_DN<4>")
	)
	(segment
		(start 349.608394 -68.54444)
		(end 351.811082 -68.54444)
		(width 0.13208)
		(layer "F.Cu")
		(net "DMI_CPU0_PCH_TX_DN<3>")
	)
	(segment
		(start 362.399834 -228.1809)
		(end 362.400088 -228.180646)
		(width 0.13208)
		(layer "F.Cu")
		(net "DMI_CPU0_PCH_TX_DN<3>")
	)
	(segment
		(start 349.280734 -68.21678)
		(end 349.608394 -68.54444)
		(width 0.13208)
		(layer "F.Cu")
		(net "DMI_CPU0_PCH_TX_DN<3>")
	)
	(segment
		(start 362.400088 -228.180646)
		(end 362.400088 -227.64496)
		(width 0.13208)
		(layer "F.Cu")
		(net "DMI_CPU0_PCH_TX_DN<3>")
	)
	(segment
		(start 351.811082 -68.54444)
		(end 352.113342 -68.24218)
		(width 0.13208)
		(layer "F.Cu")
		(net "DMI_CPU0_PCH_TX_DN<3>")
	)
	(segment
		(start 368.30635 -229.77094)
		(end 368.321082 -229.762304)
		(width 0.0889)
		(layer "In6.Cu")
		(net "DMI_CPU0_PCH_TX_DN<3>")
	)
	(segment
		(start 385.400296 -199.084692)
		(end 390.529318 -191.75984)
		(width 0.14732)
		(layer "In6.Cu")
		(net "DMI_CPU0_PCH_TX_DN<3>")
	)
	(segment
		(start 386.719572 -144.583658)
		(end 354.852478 -79.550514)
		(width 0.14732)
		(layer "In6.Cu")
		(net "DMI_CPU0_PCH_TX_DN<3>")
	)
	(segment
		(start 372.541546 -219.18676)
		(end 372.550436 -219.18168)
		(width 0.0889)
		(layer "In6.Cu")
		(net "DMI_CPU0_PCH_TX_DN<3>")
	)
	(segment
		(start 374.75033 -211.75853)
		(end 374.75033 -209.848704)
		(width 0.14732)
		(layer "In6.Cu")
		(net "DMI_CPU0_PCH_TX_DN<3>")
	)
	(segment
		(start 370.673122 -224.063814)
		(end 370.676932 -224.061528)
		(width 0.0889)
		(layer "In6.Cu")
		(net "DMI_CPU0_PCH_TX_DN<3>")
	)
	(segment
		(start 369.543584 -227.659184)
		(end 369.543584 -227.636324)
		(width 0.0889)
		(layer "In6.Cu")
		(net "DMI_CPU0_PCH_TX_DN<3>")
	)
	(segment
		(start 352.407982 -68.53682)
		(end 352.113342 -68.24218)
		(width 0.14732)
		(layer "In6.Cu")
		(net "DMI_CPU0_PCH_TX_DN<3>")
	)
	(segment
		(start 367.372392 -229.767384)
		(end 367.379758 -229.763066)
		(width 0.0889)
		(layer "In6.Cu")
		(net "DMI_CPU0_PCH_TX_DN<3>")
	)
	(segment
		(start 381.688848 -201.68362)
		(end 385.400296 -199.084692)
		(width 0.14732)
		(layer "In6.Cu")
		(net "DMI_CPU0_PCH_TX_DN<3>")
	)
	(segment
		(start 374.75033 -211.780628)
		(end 374.75033 -211.75853)
		(width 0.0889)
		(layer "In6.Cu")
		(net "DMI_CPU0_PCH_TX_DN<3>")
	)
	(segment
		(start 353.038156 -68.844668)
		(end 352.730308 -68.53682)
		(width 0.14732)
		(layer "In6.Cu")
		(net "DMI_CPU0_PCH_TX_DN<3>")
	)
	(segment
		(start 373.011192 -218.372944)
		(end 373.026178 -218.364308)
		(width 0.0889)
		(layer "In6.Cu")
		(net "DMI_CPU0_PCH_TX_DN<3>")
	)
	(segment
		(start 372.071392 -221.628462)
		(end 372.078758 -221.624144)
		(width 0.0889)
		(layer "In6.Cu")
		(net "DMI_CPU0_PCH_TX_DN<3>")
	)
	(segment
		(start 374.70842 -214.390732)
		(end 374.70842 -212.908642)
		(width 0.0889)
		(layer "In6.Cu")
		(net "DMI_CPU0_PCH_TX_DN<3>")
	)
	(segment
		(start 378.60986 -203.839572)
		(end 381.688848 -201.68362)
		(width 0.14732)
		(layer "In6.Cu")
		(net "DMI_CPU0_PCH_TX_DN<3>")
	)
	(segment
		(start 365.406432 -230.57612)
		(end 365.421164 -230.584756)
		(width 0.0889)
		(layer "In6.Cu")
		(net "DMI_CPU0_PCH_TX_DN<3>")
	)
	(segment
		(start 370.95303 -225.225356)
		(end 370.95303 -225.187764)
		(width 0.0889)
		(layer "In6.Cu")
		(net "DMI_CPU0_PCH_TX_DN<3>")
	)
	(segment
		(start 374.708674 -212.132672)
		(end 374.70842 -212.132418)
		(width 0.0889)
		(layer "In6.Cu")
		(net "DMI_CPU0_PCH_TX_DN<3>")
	)
	(segment
		(start 370.670328 -224.065338)
		(end 370.673122 -224.063814)
		(width 0.0889)
		(layer "In6.Cu")
		(net "DMI_CPU0_PCH_TX_DN<3>")
	)
	(segment
		(start 374.75033 -209.848704)
		(end 374.86717 -209.185764)
		(width 0.14732)
		(layer "In6.Cu")
		(net "DMI_CPU0_PCH_TX_DN<3>")
	)
	(segment
		(start 370.661946 -225.69805)
		(end 370.670836 -225.69297)
		(width 0.0889)
		(layer "In6.Cu")
		(net "DMI_CPU0_PCH_TX_DN<3>")
	)
	(segment
		(start 368.3254 -229.759764)
		(end 368.327178 -229.758748)
		(width 0.0889)
		(layer "In6.Cu")
		(net "DMI_CPU0_PCH_TX_DN<3>")
	)
	(segment
		(start 363.520736 -228.944932)
		(end 363.52607 -228.94798)
		(width 0.0889)
		(layer "In6.Cu")
		(net "DMI_CPU0_PCH_TX_DN<3>")
	)
	(segment
		(start 372.078758 -221.624144)
		(end 372.080282 -221.623382)
		(width 0.0889)
		(layer "In6.Cu")
		(net "DMI_CPU0_PCH_TX_DN<3>")
	)
	(segment
		(start 368.321082 -229.762304)
		(end 368.323368 -229.761034)
		(width 0.0889)
		(layer "In6.Cu")
		(net "DMI_CPU0_PCH_TX_DN<3>")
	)
	(segment
		(start 373.019574 -216.740486)
		(end 373.020336 -216.739978)
		(width 0.0889)
		(layer "In6.Cu")
		(net "DMI_CPU0_PCH_TX_DN<3>")
	)
	(segment
		(start 363.056678 -228.134672)
		(end 363.065568 -228.139752)
		(width 0.0889)
		(layer "In6.Cu")
		(net "DMI_CPU0_PCH_TX_DN<3>")
	)
	(segment
		(start 374.86717 -209.185764)
		(end 375.364248 -208.475834)
		(width 0.14732)
		(layer "In6.Cu")
		(net "DMI_CPU0_PCH_TX_DN<3>")
	)
	(segment
		(start 374.70842 -212.908642)
		(end 374.708674 -212.908388)
		(width 0.0889)
		(layer "In6.Cu")
		(net "DMI_CPU0_PCH_TX_DN<3>")
	)
	(segment
		(start 373.954548 -215.11514)
		(end 373.960644 -215.111584)
		(width 0.0889)
		(layer "In6.Cu")
		(net "DMI_CPU0_PCH_TX_DN<3>")
	)
	(segment
		(start 363.536484 -228.95433)
		(end 363.535722 -228.953568)
		(width 0.0889)
		(layer "In6.Cu")
		(net "DMI_CPU0_PCH_TX_DN<3>")
	)
	(segment
		(start 374.70842 -212.132418)
		(end 374.70842 -211.822538)
		(width 0.0889)
		(layer "In6.Cu")
		(net "DMI_CPU0_PCH_TX_DN<3>")
	)
	(segment
		(start 354.852478 -79.550514)
		(end 353.038156 -71.726806)
		(width 0.14732)
		(layer "In6.Cu")
		(net "DMI_CPU0_PCH_TX_DN<3>")
	)
	(segment
		(start 373.481346 -215.931242)
		(end 373.490236 -215.926162)
		(width 0.0889)
		(layer "In6.Cu")
		(net "DMI_CPU0_PCH_TX_DN<3>")
	)
	(segment
		(start 370.200682 -226.506786)
		(end 370.201444 -226.506278)
		(width 0.0889)
		(layer "In6.Cu")
		(net "DMI_CPU0_PCH_TX_DN<3>")
	)
	(segment
		(start 371.601746 -222.442278)
		(end 371.610636 -222.437198)
		(width 0.0889)
		(layer "In6.Cu")
		(net "DMI_CPU0_PCH_TX_DN<3>")
	)
	(segment
		(start 370.670836 -224.7138)
		(end 370.661946 -224.70872)
		(width 0.0889)
		(layer "In6.Cu")
		(net "DMI_CPU0_PCH_TX_DN<3>")
	)
	(segment
		(start 371.893084 -220.32849)
		(end 371.893084 -220.311218)
		(width 0.0889)
		(layer "In6.Cu")
		(net "DMI_CPU0_PCH_TX_DN<3>")
	)
	(segment
		(start 363.996478 -229.762304)
		(end 364.005368 -229.767384)
		(width 0.0889)
		(layer "In6.Cu")
		(net "DMI_CPU0_PCH_TX_DN<3>")
	)
	(segment
		(start 392.783568 -178.976274)
		(end 386.719572 -144.583658)
		(width 0.14732)
		(layer "In6.Cu")
		(net "DMI_CPU0_PCH_TX_DN<3>")
	)
	(segment
		(start 374.708674 -212.908388)
		(end 374.708674 -212.132672)
		(width 0.0889)
		(layer "In6.Cu")
		(net "DMI_CPU0_PCH_TX_DN<3>")
	)
	(segment
		(start 374.70842 -211.822538)
		(end 374.75033 -211.780628)
		(width 0.0889)
		(layer "In6.Cu")
		(net "DMI_CPU0_PCH_TX_DN<3>")
	)
	(segment
		(start 367.19383 -230.102156)
		(end 367.19383 -230.086662)
		(width 0.0889)
		(layer "In6.Cu")
		(net "DMI_CPU0_PCH_TX_DN<3>")
	)
	(segment
		(start 373.020336 -217.388694)
		(end 373.011446 -217.383614)
		(width 0.0889)
		(layer "In6.Cu")
		(net "DMI_CPU0_PCH_TX_DN<3>")
	)
	(segment
		(start 372.081044 -219.994988)
		(end 372.086378 -219.99194)
		(width 0.0889)
		(layer "In6.Cu")
		(net "DMI_CPU0_PCH_TX_DN<3>")
	)
	(segment
		(start 367.379758 -229.763066)
		(end 367.381282 -229.762304)
		(width 0.0889)
		(layer "In6.Cu")
		(net "DMI_CPU0_PCH_TX_DN<3>")
	)
	(segment
		(start 371.89283 -221.963234)
		(end 371.89283 -221.94774)
		(width 0.0889)
		(layer "In6.Cu")
		(net "DMI_CPU0_PCH_TX_DN<3>")
	)
	(segment
		(start 366.346232 -230.57612)
		(end 366.360964 -230.584756)
		(width 0.0889)
		(layer "In6.Cu")
		(net "DMI_CPU0_PCH_TX_DN<3>")
	)
	(segment
		(start 369.07343 -228.474524)
		(end 369.07343 -228.45903)
		(width 0.0889)
		(layer "In6.Cu")
		(net "DMI_CPU0_PCH_TX_DN<3>")
	)
	(segment
		(start 372.83263 -218.707716)
		(end 372.83263 -218.692222)
		(width 0.0889)
		(layer "In6.Cu")
		(net "DMI_CPU0_PCH_TX_DN<3>")
	)
	(segment
		(start 362.556552 -227.373942)
		(end 362.63453 -227.353114)
		(width 0.0889)
		(layer "In6.Cu")
		(net "DMI_CPU0_PCH_TX_DN<3>")
	)
	(segment
		(start 375.364248 -208.475834)
		(end 376.917712 -206.25689)
		(width 0.14732)
		(layer "In6.Cu")
		(net "DMI_CPU0_PCH_TX_DN<3>")
	)
	(segment
		(start 353.038156 -71.726806)
		(end 353.038156 -68.844668)
		(width 0.14732)
		(layer "In6.Cu")
		(net "DMI_CPU0_PCH_TX_DN<3>")
	)
	(segment
		(start 371.131846 -223.256348)
		(end 371.140736 -223.251268)
		(width 0.0889)
		(layer "In6.Cu")
		(net "DMI_CPU0_PCH_TX_DN<3>")
	)
	(segment
		(start 372.080282 -219.995496)
		(end 372.081044 -219.994988)
		(width 0.0889)
		(layer "In6.Cu")
		(net "DMI_CPU0_PCH_TX_DN<3>")
	)
	(segment
		(start 376.917712 -206.25689)
		(end 378.60986 -203.839572)
		(width 0.14732)
		(layer "In6.Cu")
		(net "DMI_CPU0_PCH_TX_DN<3>")
	)
	(segment
		(start 372.080282 -221.623382)
		(end 372.081044 -221.622874)
		(width 0.0889)
		(layer "In6.Cu")
		(net "DMI_CPU0_PCH_TX_DN<3>")
	)
	(segment
		(start 372.081044 -221.622874)
		(end 372.086378 -221.619826)
		(width 0.0889)
		(layer "In6.Cu")
		(net "DMI_CPU0_PCH_TX_DN<3>")
	)
	(segment
		(start 370.201444 -226.506278)
		(end 370.206778 -226.50323)
		(width 0.0889)
		(layer "In6.Cu")
		(net "DMI_CPU0_PCH_TX_DN<3>")
	)
	(segment
		(start 368.782346 -228.953568)
		(end 368.791236 -228.948488)
		(width 0.0889)
		(layer "In6.Cu")
		(net "DMI_CPU0_PCH_TX_DN<3>")
	)
	(segment
		(start 369.730782 -227.320602)
		(end 369.736878 -227.317046)
		(width 0.0889)
		(layer "In6.Cu")
		(net "DMI_CPU0_PCH_TX_DN<3>")
	)
	(segment
		(start 373.017542 -216.741502)
		(end 373.019574 -216.740486)
		(width 0.0889)
		(layer "In6.Cu")
		(net "DMI_CPU0_PCH_TX_DN<3>")
	)
	(segment
		(start 369.251992 -228.139752)
		(end 369.260882 -228.134672)
		(width 0.0889)
		(layer "In6.Cu")
		(net "DMI_CPU0_PCH_TX_DN<3>")
	)
	(segment
		(start 352.730308 -68.53682)
		(end 352.407982 -68.53682)
		(width 0.14732)
		(layer "In6.Cu")
		(net "DMI_CPU0_PCH_TX_DN<3>")
	)
	(segment
		(start 373.772684 -215.44661)
		(end 373.772684 -215.435688)
		(width 0.0889)
		(layer "In6.Cu")
		(net "DMI_CPU0_PCH_TX_DN<3>")
	)
	(segment
		(start 373.011446 -216.745058)
		(end 373.017542 -216.741502)
		(width 0.0889)
		(layer "In6.Cu")
		(net "DMI_CPU0_PCH_TX_DN<3>")
	)
	(segment
		(start 373.302784 -216.260426)
		(end 373.302784 -216.25052)
		(width 0.0889)
		(layer "In6.Cu")
		(net "DMI_CPU0_PCH_TX_DN<3>")
	)
	(segment
		(start 362.400088 -227.64496)
		(end 362.556552 -227.373942)
		(width 0.0889)
		(layer "In6.Cu")
		(net "DMI_CPU0_PCH_TX_DN<3>")
	)
	(segment
		(start 373.772684 -215.435688)
		(end 373.772176 -215.436704)
		(width 0.0889)
		(layer "In6.Cu")
		(net "DMI_CPU0_PCH_TX_DN<3>")
	)
	(segment
		(start 363.714284 -229.272846)
		(end 363.714284 -229.28834)
		(width 0.0889)
		(layer "In6.Cu")
		(net "DMI_CPU0_PCH_TX_DN<3>")
	)
	(segment
		(start 363.527594 -228.948996)
		(end 363.536484 -228.95433)
		(width 0.0889)
		(layer "In6.Cu")
		(net "DMI_CPU0_PCH_TX_DN<3>")
	)
	(segment
		(start 370.661946 -224.070164)
		(end 370.670328 -224.065338)
		(width 0.0889)
		(layer "In6.Cu")
		(net "DMI_CPU0_PCH_TX_DN<3>")
	)
	(segment
		(start 368.323368 -229.761034)
		(end 368.3254 -229.759764)
		(width 0.0889)
		(layer "In6.Cu")
		(net "DMI_CPU0_PCH_TX_DN<3>")
	)
	(segment
		(start 371.423184 -222.780098)
		(end 371.423184 -222.761556)
		(width 0.0889)
		(layer "In6.Cu")
		(net "DMI_CPU0_PCH_TX_DN<3>")
	)
	(segment
		(start 362.774484 -227.636324)
		(end 362.774484 -227.667058)
		(width 0.0889)
		(layer "In6.Cu")
		(net "DMI_CPU0_PCH_TX_DN<3>")
	)
	(segment
		(start 374.076976 -215.022176)
		(end 374.70842 -214.390732)
		(width 0.0889)
		(layer "In6.Cu")
		(net "DMI_CPU0_PCH_TX_DN<3>")
	)
	(segment
		(start 370.013484 -226.831144)
		(end 370.013484 -226.822508)
		(width 0.0889)
		(layer "In6.Cu")
		(net "DMI_CPU0_PCH_TX_DN<3>")
	)
	(segment
		(start 390.529318 -191.75984)
		(end 392.783568 -178.976274)
		(width 0.14732)
		(layer "In6.Cu")
		(net "DMI_CPU0_PCH_TX_DN<3>")
	)
	(segment
		(start 363.52607 -228.94798)
		(end 363.527594 -228.948996)
		(width 0.0889)
		(layer "In6.Cu")
		(net "DMI_CPU0_PCH_TX_DN<3>")
	)
	(arc
		(start 373.011446 -217.383614)
		(mid 372.832849 -217.064336)
		(end 373.011446 -216.745058)
		(width 0.0889)
		(layer "In6.Cu")
		(net "DMI_CPU0_PCH_TX_DN<3>")
	)
	(arc
		(start 370.670836 -225.69297)
		(mid 370.872118 -225.495483)
		(end 370.95303 -225.225356)
		(width 0.0889)
		(layer "In6.Cu")
		(net "DMI_CPU0_PCH_TX_DN<3>")
	)
	(arc
		(start 372.086378 -221.619826)
		(mid 372.362941 -221.130332)
		(end 372.080282 -220.644212)
		(width 0.0889)
		(layer "In6.Cu")
		(net "DMI_CPU0_PCH_TX_DN<3>")
	)
	(arc
		(start 363.24413 -228.45903)
		(mid 363.318121 -228.738596)
		(end 363.520736 -228.944932)
		(width 0.0889)
		(layer "In6.Cu")
		(net "DMI_CPU0_PCH_TX_DN<3>")
	)
	(arc
		(start 372.550436 -219.18168)
		(mid 372.753259 -218.981449)
		(end 372.83263 -218.707716)
		(width 0.0889)
		(layer "In6.Cu")
		(net "DMI_CPU0_PCH_TX_DN<3>")
	)
	(arc
		(start 364.005368 -229.767384)
		(mid 364.136282 -229.903744)
		(end 364.18393 -230.086662)
		(width 0.0889)
		(layer "In6.Cu")
		(net "DMI_CPU0_PCH_TX_DN<3>")
	)
	(arc
		(start 370.483638 -226.002596)
		(mid 370.534692 -225.828016)
		(end 370.661946 -225.69805)
		(width 0.0889)
		(layer "In6.Cu")
		(net "DMI_CPU0_PCH_TX_DN<3>")
	)
	(arc
		(start 372.086378 -219.99194)
		(mid 372.288965 -219.785589)
		(end 372.362984 -219.506038)
		(width 0.0889)
		(layer "In6.Cu")
		(net "DMI_CPU0_PCH_TX_DN<3>")
	)
	(arc
		(start 373.020336 -216.739978)
		(mid 373.224671 -216.537373)
		(end 373.302784 -216.260426)
		(width 0.0889)
		(layer "In6.Cu")
		(net "DMI_CPU0_PCH_TX_DN<3>")
	)
	(arc
		(start 370.013484 -226.822508)
		(mid 370.065754 -226.640143)
		(end 370.200682 -226.506786)
		(width 0.0889)
		(layer "In6.Cu")
		(net "DMI_CPU0_PCH_TX_DN<3>")
	)
	(arc
		(start 372.080282 -220.644212)
		(mid 371.945349 -220.510858)
		(end 371.893084 -220.32849)
		(width 0.0889)
		(layer "In6.Cu")
		(net "DMI_CPU0_PCH_TX_DN<3>")
	)
	(arc
		(start 373.772176 -215.436704)
		(mid 373.820945 -215.251868)
		(end 373.954548 -215.11514)
		(width 0.0889)
		(layer "In6.Cu")
		(net "DMI_CPU0_PCH_TX_DN<3>")
	)
	(arc
		(start 370.953284 -223.575626)
		(mid 371.000963 -223.392726)
		(end 371.131846 -223.256348)
		(width 0.0889)
		(layer "In6.Cu")
		(net "DMI_CPU0_PCH_TX_DN<3>")
	)
	(arc
		(start 365.421164 -230.584756)
		(mid 365.697639 -230.652076)
		(end 365.971836 -230.57612)
		(width 0.0889)
		(layer "In6.Cu")
		(net "DMI_CPU0_PCH_TX_DN<3>")
	)
	(arc
		(start 373.302784 -216.25052)
		(mid 373.350463 -216.06762)
		(end 373.481346 -215.931242)
		(width 0.0889)
		(layer "In6.Cu")
		(net "DMI_CPU0_PCH_TX_DN<3>")
	)
	(arc
		(start 372.362984 -219.506038)
		(mid 372.410663 -219.323138)
		(end 372.541546 -219.18676)
		(width 0.0889)
		(layer "In6.Cu")
		(net "DMI_CPU0_PCH_TX_DN<3>")
	)
	(arc
		(start 368.603784 -229.272846)
		(mid 368.651463 -229.089946)
		(end 368.782346 -228.953568)
		(width 0.0889)
		(layer "In6.Cu")
		(net "DMI_CPU0_PCH_TX_DN<3>")
	)
	(arc
		(start 372.83263 -218.692222)
		(mid 372.880309 -218.509322)
		(end 373.011192 -218.372944)
		(width 0.0889)
		(layer "In6.Cu")
		(net "DMI_CPU0_PCH_TX_DN<3>")
	)
	(arc
		(start 373.960644 -215.111584)
		(mid 374.021728 -215.070676)
		(end 374.076976 -215.022176)
		(width 0.0889)
		(layer "In6.Cu")
		(net "DMI_CPU0_PCH_TX_DN<3>")
	)
	(arc
		(start 362.774484 -227.667058)
		(mid 362.855395 -227.937186)
		(end 363.056678 -228.134672)
		(width 0.0889)
		(layer "In6.Cu")
		(net "DMI_CPU0_PCH_TX_DN<3>")
	)
	(arc
		(start 367.381282 -229.762304)
		(mid 367.56848 -229.712161)
		(end 367.755678 -229.762304)
		(width 0.0889)
		(layer "In6.Cu")
		(net "DMI_CPU0_PCH_TX_DN<3>")
	)
	(arc
		(start 370.483384 -226.017328)
		(mid 370.483436 -226.009961)
		(end 370.483638 -226.002596)
		(width 0.0889)
		(layer "In6.Cu")
		(net "DMI_CPU0_PCH_TX_DN<3>")
	)
	(arc
		(start 371.89283 -221.94774)
		(mid 371.940509 -221.76484)
		(end 372.071392 -221.628462)
		(width 0.0889)
		(layer "In6.Cu")
		(net "DMI_CPU0_PCH_TX_DN<3>")
	)
	(arc
		(start 368.791236 -228.948488)
		(mid 368.994059 -228.748257)
		(end 369.07343 -228.474524)
		(width 0.0889)
		(layer "In6.Cu")
		(net "DMI_CPU0_PCH_TX_DN<3>")
	)
	(arc
		(start 371.893084 -220.311218)
		(mid 371.945354 -220.128853)
		(end 372.080282 -219.995496)
		(width 0.0889)
		(layer "In6.Cu")
		(net "DMI_CPU0_PCH_TX_DN<3>")
	)
	(arc
		(start 369.07343 -228.45903)
		(mid 369.121109 -228.27613)
		(end 369.251992 -228.139752)
		(width 0.0889)
		(layer "In6.Cu")
		(net "DMI_CPU0_PCH_TX_DN<3>")
	)
	(arc
		(start 367.755678 -229.762304)
		(mid 368.029877 -229.838139)
		(end 368.30635 -229.77094)
		(width 0.0889)
		(layer "In6.Cu")
		(net "DMI_CPU0_PCH_TX_DN<3>")
	)
	(arc
		(start 368.327178 -229.758748)
		(mid 368.529765 -229.552397)
		(end 368.603784 -229.272846)
		(width 0.0889)
		(layer "In6.Cu")
		(net "DMI_CPU0_PCH_TX_DN<3>")
	)
	(arc
		(start 371.610636 -222.437198)
		(mid 371.813459 -222.236967)
		(end 371.89283 -221.963234)
		(width 0.0889)
		(layer "In6.Cu")
		(net "DMI_CPU0_PCH_TX_DN<3>")
	)
	(arc
		(start 363.714284 -229.28834)
		(mid 363.793654 -229.562074)
		(end 363.996478 -229.762304)
		(width 0.0889)
		(layer "In6.Cu")
		(net "DMI_CPU0_PCH_TX_DN<3>")
	)
	(arc
		(start 370.206778 -226.50323)
		(mid 370.409365 -226.296879)
		(end 370.483384 -226.017328)
		(width 0.0889)
		(layer "In6.Cu")
		(net "DMI_CPU0_PCH_TX_DN<3>")
	)
	(arc
		(start 371.140736 -223.251268)
		(mid 371.343022 -223.052287)
		(end 371.423184 -222.780098)
		(width 0.0889)
		(layer "In6.Cu")
		(net "DMI_CPU0_PCH_TX_DN<3>")
	)
	(arc
		(start 373.490236 -215.926162)
		(mid 373.694571 -215.723557)
		(end 373.772684 -215.44661)
		(width 0.0889)
		(layer "In6.Cu")
		(net "DMI_CPU0_PCH_TX_DN<3>")
	)
	(arc
		(start 370.661946 -224.70872)
		(mid 370.48347 -224.389442)
		(end 370.661946 -224.070164)
		(width 0.0889)
		(layer "In6.Cu")
		(net "DMI_CPU0_PCH_TX_DN<3>")
	)
	(arc
		(start 369.736878 -227.317046)
		(mid 369.939465 -227.110695)
		(end 370.013484 -226.831144)
		(width 0.0889)
		(layer "In6.Cu")
		(net "DMI_CPU0_PCH_TX_DN<3>")
	)
	(arc
		(start 369.260882 -228.134672)
		(mid 369.464363 -227.933868)
		(end 369.543584 -227.659184)
		(width 0.0889)
		(layer "In6.Cu")
		(net "DMI_CPU0_PCH_TX_DN<3>")
	)
	(arc
		(start 366.360964 -230.584756)
		(mid 366.912157 -230.575958)
		(end 367.19383 -230.102156)
		(width 0.0889)
		(layer "In6.Cu")
		(net "DMI_CPU0_PCH_TX_DN<3>")
	)
	(arc
		(start 370.676932 -224.061528)
		(mid 370.879345 -223.855115)
		(end 370.953284 -223.575626)
		(width 0.0889)
		(layer "In6.Cu")
		(net "DMI_CPU0_PCH_TX_DN<3>")
	)
	(arc
		(start 365.032036 -230.57612)
		(mid 365.219234 -230.525977)
		(end 365.406432 -230.57612)
		(width 0.0889)
		(layer "In6.Cu")
		(net "DMI_CPU0_PCH_TX_DN<3>")
	)
	(arc
		(start 362.63453 -227.353114)
		(mid 362.735851 -227.479235)
		(end 362.774484 -227.636324)
		(width 0.0889)
		(layer "In6.Cu")
		(net "DMI_CPU0_PCH_TX_DN<3>")
	)
	(arc
		(start 373.026178 -218.364308)
		(mid 373.30296 -217.874797)
		(end 373.020336 -217.388694)
		(width 0.0889)
		(layer "In6.Cu")
		(net "DMI_CPU0_PCH_TX_DN<3>")
	)
	(arc
		(start 370.95303 -225.187764)
		(mid 370.87366 -224.91403)
		(end 370.670836 -224.7138)
		(width 0.0889)
		(layer "In6.Cu")
		(net "DMI_CPU0_PCH_TX_DN<3>")
	)
	(arc
		(start 363.065568 -228.139752)
		(mid 363.192822 -228.269718)
		(end 363.243876 -228.444298)
		(width 0.0889)
		(layer "In6.Cu")
		(net "DMI_CPU0_PCH_TX_DN<3>")
	)
	(arc
		(start 369.543584 -227.636324)
		(mid 369.595854 -227.453959)
		(end 369.730782 -227.320602)
		(width 0.0889)
		(layer "In6.Cu")
		(net "DMI_CPU0_PCH_TX_DN<3>")
	)
	(arc
		(start 363.243876 -228.444298)
		(mid 363.244073 -228.451663)
		(end 363.24413 -228.45903)
		(width 0.0889)
		(layer "In6.Cu")
		(net "DMI_CPU0_PCH_TX_DN<3>")
	)
	(arc
		(start 371.423184 -222.761556)
		(mid 371.470863 -222.578656)
		(end 371.601746 -222.442278)
		(width 0.0889)
		(layer "In6.Cu")
		(net "DMI_CPU0_PCH_TX_DN<3>")
	)
	(arc
		(start 364.18393 -230.086662)
		(mid 364.466643 -230.576176)
		(end 365.032036 -230.57612)
		(width 0.0889)
		(layer "In6.Cu")
		(net "DMI_CPU0_PCH_TX_DN<3>")
	)
	(arc
		(start 365.971836 -230.57612)
		(mid 366.159034 -230.525977)
		(end 366.346232 -230.57612)
		(width 0.0889)
		(layer "In6.Cu")
		(net "DMI_CPU0_PCH_TX_DN<3>")
	)
	(arc
		(start 367.19383 -230.086662)
		(mid 367.241509 -229.903762)
		(end 367.372392 -229.767384)
		(width 0.0889)
		(layer "In6.Cu")
		(net "DMI_CPU0_PCH_TX_DN<3>")
	)
	(arc
		(start 363.535722 -228.953568)
		(mid 363.666636 -229.089928)
		(end 363.714284 -229.272846)
		(width 0.0889)
		(layer "In6.Cu")
		(net "DMI_CPU0_PCH_TX_DN<3>")
	)
	(segment
		(start 346.378276 -69.9643)
		(end 346.378276 -70.050406)
		(width 0.13208)
		(layer "F.Cu")
		(net "DMI_CPU0_PCH_TX_DN<2>")
	)
	(segment
		(start 346.378276 -70.050406)
		(end 346.506038 -70.178168)
		(width 0.13208)
		(layer "F.Cu")
		(net "DMI_CPU0_PCH_TX_DN<2>")
	)
	(segment
		(start 361.92968 -228.994716)
		(end 361.92968 -228.45903)
		(width 0.13208)
		(layer "F.Cu")
		(net "DMI_CPU0_PCH_TX_DN<2>")
	)
	(segment
		(start 347.285056 -70.759066)
		(end 347.285056 -71.496936)
		(width 0.13208)
		(layer "F.Cu")
		(net "DMI_CPU0_PCH_TX_DN<2>")
	)
	(segment
		(start 346.506038 -70.178168)
		(end 346.704158 -70.178168)
		(width 0.13208)
		(layer "F.Cu")
		(net "DMI_CPU0_PCH_TX_DN<2>")
	)
	(segment
		(start 347.285056 -71.496936)
		(end 347.605096 -71.816976)
		(width 0.13208)
		(layer "F.Cu")
		(net "DMI_CPU0_PCH_TX_DN<2>")
	)
	(segment
		(start 346.704158 -70.178168)
		(end 347.285056 -70.759066)
		(width 0.13208)
		(layer "F.Cu")
		(net "DMI_CPU0_PCH_TX_DN<2>")
	)
	(segment
		(start 346.70619 -69.63664)
		(end 346.378276 -69.9643)
		(width 0.13208)
		(layer "F.Cu")
		(net "DMI_CPU0_PCH_TX_DN<2>")
	)
	(segment
		(start 361.929934 -228.99497)
		(end 361.92968 -228.994716)
		(width 0.13208)
		(layer "F.Cu")
		(net "DMI_CPU0_PCH_TX_DN<2>")
	)
	(segment
		(start 367.372646 -220.000576)
		(end 367.380774 -219.996004)
		(width 0.0889)
		(layer "In6.Cu")
		(net "DMI_CPU0_PCH_TX_DN<2>")
	)
	(segment
		(start 370.031264 -214.36838)
		(end 370.031264 -211.741258)
		(width 0.0889)
		(layer "In6.Cu")
		(net "DMI_CPU0_PCH_TX_DN<2>")
	)
	(segment
		(start 368.782346 -215.931242)
		(end 368.791236 -215.926162)
		(width 0.0889)
		(layer "In6.Cu")
		(net "DMI_CPU0_PCH_TX_DN<2>")
	)
	(segment
		(start 361.92968 -228.45903)
		(end 361.773216 -228.188012)
		(width 0.0889)
		(layer "In6.Cu")
		(net "DMI_CPU0_PCH_TX_DN<2>")
	)
	(segment
		(start 370.031264 -211.741258)
		(end 370.073174 -211.699348)
		(width 0.0889)
		(layer "In6.Cu")
		(net "DMI_CPU0_PCH_TX_DN<2>")
	)
	(segment
		(start 365.971836 -224.7138)
		(end 365.962946 -224.70872)
		(width 0.0889)
		(layer "In6.Cu")
		(net "DMI_CPU0_PCH_TX_DN<2>")
	)
	(segment
		(start 366.911636 -222.437198)
		(end 366.917732 -222.433642)
		(width 0.0889)
		(layer "In6.Cu")
		(net "DMI_CPU0_PCH_TX_DN<2>")
	)
	(segment
		(start 370.073174 -211.699348)
		(end 370.073174 -211.67725)
		(width 0.0889)
		(layer "In6.Cu")
		(net "DMI_CPU0_PCH_TX_DN<2>")
	)
	(segment
		(start 381.434086 -195.786248)
		(end 386.203952 -188.974222)
		(width 0.14732)
		(layer "In6.Cu")
		(net "DMI_CPU0_PCH_TX_DN<2>")
	)
	(segment
		(start 367.842546 -219.18676)
		(end 367.851436 -219.18168)
		(width 0.0889)
		(layer "In6.Cu")
		(net "DMI_CPU0_PCH_TX_DN<2>")
	)
	(segment
		(start 370.073174 -211.67725)
		(end 370.073174 -211.420202)
		(width 0.14732)
		(layer "In6.Cu")
		(net "DMI_CPU0_PCH_TX_DN<2>")
	)
	(segment
		(start 370.073428 -209.455766)
		(end 370.37899 -207.71993)
		(width 0.14732)
		(layer "In6.Cu")
		(net "DMI_CPU0_PCH_TX_DN<2>")
	)
	(segment
		(start 362.495084 -226.846638)
		(end 362.495084 -226.831144)
		(width 0.0889)
		(layer "In6.Cu")
		(net "DMI_CPU0_PCH_TX_DN<2>")
	)
	(segment
		(start 348.974918 -80.03667)
		(end 347.310456 -74.855324)
		(width 0.14732)
		(layer "In6.Cu")
		(net "DMI_CPU0_PCH_TX_DN<2>")
	)
	(segment
		(start 366.724184 -222.77578)
		(end 366.724184 -222.761556)
		(width 0.0889)
		(layer "In6.Cu")
		(net "DMI_CPU0_PCH_TX_DN<2>")
	)
	(segment
		(start 370.073428 -211.419948)
		(end 370.073428 -209.455766)
		(width 0.14732)
		(layer "In6.Cu")
		(net "DMI_CPU0_PCH_TX_DN<2>")
	)
	(segment
		(start 388.09676 -178.237134)
		(end 382.788414 -148.139658)
		(width 0.14732)
		(layer "In6.Cu")
		(net "DMI_CPU0_PCH_TX_DN<2>")
	)
	(segment
		(start 368.603784 -217.878406)
		(end 368.603784 -217.864182)
		(width 0.0889)
		(layer "In6.Cu")
		(net "DMI_CPU0_PCH_TX_DN<2>")
	)
	(segment
		(start 370.37899 -207.71993)
		(end 375.28754 -200.710292)
		(width 0.14732)
		(layer "In6.Cu")
		(net "DMI_CPU0_PCH_TX_DN<2>")
	)
	(segment
		(start 367.380774 -219.996004)
		(end 367.381536 -219.995496)
		(width 0.0889)
		(layer "In6.Cu")
		(net "DMI_CPU0_PCH_TX_DN<2>")
	)
	(segment
		(start 365.023146 -225.69805)
		(end 365.032036 -225.69297)
		(width 0.0889)
		(layer "In6.Cu")
		(net "DMI_CPU0_PCH_TX_DN<2>")
	)
	(segment
		(start 368.319558 -218.368626)
		(end 368.321082 -218.367864)
		(width 0.0889)
		(layer "In6.Cu")
		(net "DMI_CPU0_PCH_TX_DN<2>")
	)
	(segment
		(start 366.25403 -225.225356)
		(end 366.25403 -225.187764)
		(width 0.0889)
		(layer "In6.Cu")
		(net "DMI_CPU0_PCH_TX_DN<2>")
	)
	(segment
		(start 362.211874 -227.32111)
		(end 362.21289 -227.320602)
		(width 0.0889)
		(layer "In6.Cu")
		(net "DMI_CPU0_PCH_TX_DN<2>")
	)
	(segment
		(start 366.254284 -223.585532)
		(end 366.254284 -223.56699)
		(width 0.0889)
		(layer "In6.Cu")
		(net "DMI_CPU0_PCH_TX_DN<2>")
	)
	(segment
		(start 362.204 -227.325682)
		(end 362.211874 -227.32111)
		(width 0.0889)
		(layer "In6.Cu")
		(net "DMI_CPU0_PCH_TX_DN<2>")
	)
	(segment
		(start 368.321844 -216.73947)
		(end 368.327178 -216.736422)
		(width 0.0889)
		(layer "In6.Cu")
		(net "DMI_CPU0_PCH_TX_DN<2>")
	)
	(segment
		(start 375.28754 -200.710292)
		(end 379.364494 -197.85584)
		(width 0.14732)
		(layer "In6.Cu")
		(net "DMI_CPU0_PCH_TX_DN<2>")
	)
	(segment
		(start 347.310456 -74.855324)
		(end 347.310456 -72.111616)
		(width 0.14732)
		(layer "In6.Cu")
		(net "DMI_CPU0_PCH_TX_DN<2>")
	)
	(segment
		(start 361.773216 -228.188012)
		(end 361.797346 -228.099112)
		(width 0.0889)
		(layer "In6.Cu")
		(net "DMI_CPU0_PCH_TX_DN<2>")
	)
	(segment
		(start 367.381536 -220.644212)
		(end 367.372646 -220.639132)
		(width 0.0889)
		(layer "In6.Cu")
		(net "DMI_CPU0_PCH_TX_DN<2>")
	)
	(segment
		(start 365.962946 -224.070164)
		(end 365.971836 -224.065084)
		(width 0.0889)
		(layer "In6.Cu")
		(net "DMI_CPU0_PCH_TX_DN<2>")
	)
	(segment
		(start 379.364494 -197.85584)
		(end 381.434086 -195.786248)
		(width 0.14732)
		(layer "In6.Cu")
		(net "DMI_CPU0_PCH_TX_DN<2>")
	)
	(segment
		(start 367.372646 -221.628462)
		(end 367.381536 -221.623382)
		(width 0.0889)
		(layer "In6.Cu")
		(net "DMI_CPU0_PCH_TX_DN<2>")
	)
	(segment
		(start 382.788414 -148.139658)
		(end 348.974918 -80.03667)
		(width 0.14732)
		(layer "In6.Cu")
		(net "DMI_CPU0_PCH_TX_DN<2>")
	)
	(segment
		(start 368.321082 -218.367864)
		(end 368.321844 -218.367356)
		(width 0.0889)
		(layer "In6.Cu")
		(net "DMI_CPU0_PCH_TX_DN<2>")
	)
	(segment
		(start 369.07343 -215.452198)
		(end 369.07343 -215.436704)
		(width 0.0889)
		(layer "In6.Cu")
		(net "DMI_CPU0_PCH_TX_DN<2>")
	)
	(segment
		(start 364.551468 -226.512882)
		(end 364.567978 -226.50323)
		(width 0.0889)
		(layer "In6.Cu")
		(net "DMI_CPU0_PCH_TX_DN<2>")
	)
	(segment
		(start 368.321082 -216.739978)
		(end 368.321844 -216.73947)
		(width 0.0889)
		(layer "In6.Cu")
		(net "DMI_CPU0_PCH_TX_DN<2>")
	)
	(segment
		(start 365.406432 -225.69297)
		(end 365.421164 -225.701606)
		(width 0.0889)
		(layer "In6.Cu")
		(net "DMI_CPU0_PCH_TX_DN<2>")
	)
	(segment
		(start 368.321844 -218.367356)
		(end 368.327178 -218.364308)
		(width 0.0889)
		(layer "In6.Cu")
		(net "DMI_CPU0_PCH_TX_DN<2>")
	)
	(segment
		(start 368.133884 -217.072972)
		(end 368.133884 -217.0557)
		(width 0.0889)
		(layer "In6.Cu")
		(net "DMI_CPU0_PCH_TX_DN<2>")
	)
	(segment
		(start 347.310456 -72.111616)
		(end 347.605096 -71.816976)
		(width 0.14732)
		(layer "In6.Cu")
		(net "DMI_CPU0_PCH_TX_DN<2>")
	)
	(segment
		(start 369.377214 -215.02243)
		(end 370.031264 -214.36838)
		(width 0.0889)
		(layer "In6.Cu")
		(net "DMI_CPU0_PCH_TX_DN<2>")
	)
	(segment
		(start 370.073174 -211.420202)
		(end 370.073428 -211.419948)
		(width 0.14732)
		(layer "In6.Cu")
		(net "DMI_CPU0_PCH_TX_DN<2>")
	)
	(segment
		(start 367.663984 -221.14383)
		(end 367.663984 -221.115382)
		(width 0.0889)
		(layer "In6.Cu")
		(net "DMI_CPU0_PCH_TX_DN<2>")
	)
	(segment
		(start 369.251992 -215.117426)
		(end 369.26012 -215.112092)
		(width 0.0889)
		(layer "In6.Cu")
		(net "DMI_CPU0_PCH_TX_DN<2>")
	)
	(segment
		(start 367.663984 -219.515944)
		(end 367.663984 -219.506038)
		(width 0.0889)
		(layer "In6.Cu")
		(net "DMI_CPU0_PCH_TX_DN<2>")
	)
	(segment
		(start 368.13363 -218.707716)
		(end 368.13363 -218.692222)
		(width 0.0889)
		(layer "In6.Cu")
		(net "DMI_CPU0_PCH_TX_DN<2>")
	)
	(segment
		(start 386.203952 -188.974222)
		(end 388.09676 -178.237134)
		(width 0.14732)
		(layer "In6.Cu")
		(net "DMI_CPU0_PCH_TX_DN<2>")
	)
	(segment
		(start 366.902746 -222.442278)
		(end 366.911636 -222.437198)
		(width 0.0889)
		(layer "In6.Cu")
		(net "DMI_CPU0_PCH_TX_DN<2>")
	)
	(segment
		(start 362.673646 -226.511866)
		(end 362.682536 -226.506786)
		(width 0.0889)
		(layer "In6.Cu")
		(net "DMI_CPU0_PCH_TX_DN<2>")
	)
	(segment
		(start 368.312192 -218.372944)
		(end 368.319558 -218.368626)
		(width 0.0889)
		(layer "In6.Cu")
		(net "DMI_CPU0_PCH_TX_DN<2>")
	)
	(arc
		(start 365.032036 -225.69297)
		(mid 365.219234 -225.642827)
		(end 365.406432 -225.69297)
		(width 0.0889)
		(layer "In6.Cu")
		(net "DMI_CPU0_PCH_TX_DN<2>")
	)
	(arc
		(start 368.791236 -215.926162)
		(mid 368.994059 -215.725931)
		(end 369.07343 -215.452198)
		(width 0.0889)
		(layer "In6.Cu")
		(net "DMI_CPU0_PCH_TX_DN<2>")
	)
	(arc
		(start 361.797346 -228.099112)
		(mid 361.806048 -228.092465)
		(end 361.814618 -228.08565)
		(width 0.0889)
		(layer "In6.Cu")
		(net "DMI_CPU0_PCH_TX_DN<2>")
	)
	(arc
		(start 368.321082 -217.388694)
		(mid 368.186149 -217.25534)
		(end 368.133884 -217.072972)
		(width 0.0889)
		(layer "In6.Cu")
		(net "DMI_CPU0_PCH_TX_DN<2>")
	)
	(arc
		(start 361.814618 -228.08565)
		(mid 361.970092 -227.889251)
		(end 362.025438 -227.64496)
		(width 0.0889)
		(layer "In6.Cu")
		(net "DMI_CPU0_PCH_TX_DN<2>")
	)
	(arc
		(start 364.567978 -226.50323)
		(mid 364.770565 -226.296879)
		(end 364.844584 -226.017328)
		(width 0.0889)
		(layer "In6.Cu")
		(net "DMI_CPU0_PCH_TX_DN<2>")
	)
	(arc
		(start 367.663984 -221.115382)
		(mid 367.583822 -220.843193)
		(end 367.381536 -220.644212)
		(width 0.0889)
		(layer "In6.Cu")
		(net "DMI_CPU0_PCH_TX_DN<2>")
	)
	(arc
		(start 365.421164 -225.701606)
		(mid 365.697605 -225.768772)
		(end 365.971836 -225.69297)
		(width 0.0889)
		(layer "In6.Cu")
		(net "DMI_CPU0_PCH_TX_DN<2>")
	)
	(arc
		(start 367.372646 -220.639132)
		(mid 367.194049 -220.319854)
		(end 367.372646 -220.000576)
		(width 0.0889)
		(layer "In6.Cu")
		(net "DMI_CPU0_PCH_TX_DN<2>")
	)
	(arc
		(start 363.056932 -226.506786)
		(mid 363.339634 -226.582562)
		(end 363.622336 -226.506786)
		(width 0.0889)
		(layer "In6.Cu")
		(net "DMI_CPU0_PCH_TX_DN<2>")
	)
	(arc
		(start 365.784638 -224.382838)
		(mid 365.833745 -224.203649)
		(end 365.962946 -224.070164)
		(width 0.0889)
		(layer "In6.Cu")
		(net "DMI_CPU0_PCH_TX_DN<2>")
	)
	(arc
		(start 365.962946 -224.70872)
		(mid 365.834627 -224.576748)
		(end 365.784638 -224.399602)
		(width 0.0889)
		(layer "In6.Cu")
		(net "DMI_CPU0_PCH_TX_DN<2>")
	)
	(arc
		(start 368.133884 -217.0557)
		(mid 368.186154 -216.873335)
		(end 368.321082 -216.739978)
		(width 0.0889)
		(layer "In6.Cu")
		(net "DMI_CPU0_PCH_TX_DN<2>")
	)
	(arc
		(start 367.194084 -221.94774)
		(mid 367.241763 -221.76484)
		(end 367.372646 -221.628462)
		(width 0.0889)
		(layer "In6.Cu")
		(net "DMI_CPU0_PCH_TX_DN<2>")
	)
	(arc
		(start 368.327178 -216.736422)
		(mid 368.529765 -216.530071)
		(end 368.603784 -216.25052)
		(width 0.0889)
		(layer "In6.Cu")
		(net "DMI_CPU0_PCH_TX_DN<2>")
	)
	(arc
		(start 369.07343 -215.436704)
		(mid 369.121109 -215.253804)
		(end 369.251992 -215.117426)
		(width 0.0889)
		(layer "In6.Cu")
		(net "DMI_CPU0_PCH_TX_DN<2>")
	)
	(arc
		(start 368.13363 -218.692222)
		(mid 368.181309 -218.509322)
		(end 368.312192 -218.372944)
		(width 0.0889)
		(layer "In6.Cu")
		(net "DMI_CPU0_PCH_TX_DN<2>")
	)
	(arc
		(start 365.784638 -224.399602)
		(mid 365.784544 -224.39122)
		(end 365.784638 -224.382838)
		(width 0.0889)
		(layer "In6.Cu")
		(net "DMI_CPU0_PCH_TX_DN<2>")
	)
	(arc
		(start 369.26012 -215.112092)
		(mid 369.321604 -215.071097)
		(end 369.377214 -215.02243)
		(width 0.0889)
		(layer "In6.Cu")
		(net "DMI_CPU0_PCH_TX_DN<2>")
	)
	(arc
		(start 368.327178 -218.364308)
		(mid 368.529765 -218.157957)
		(end 368.603784 -217.878406)
		(width 0.0889)
		(layer "In6.Cu")
		(net "DMI_CPU0_PCH_TX_DN<2>")
	)
	(arc
		(start 363.996732 -226.506786)
		(mid 364.273291 -226.582529)
		(end 364.551468 -226.512882)
		(width 0.0889)
		(layer "In6.Cu")
		(net "DMI_CPU0_PCH_TX_DN<2>")
	)
	(arc
		(start 362.495084 -226.831144)
		(mid 362.542763 -226.648244)
		(end 362.673646 -226.511866)
		(width 0.0889)
		(layer "In6.Cu")
		(net "DMI_CPU0_PCH_TX_DN<2>")
	)
	(arc
		(start 362.025438 -227.64496)
		(mid 362.073117 -227.46206)
		(end 362.204 -227.325682)
		(width 0.0889)
		(layer "In6.Cu")
		(net "DMI_CPU0_PCH_TX_DN<2>")
	)
	(arc
		(start 367.381536 -221.623382)
		(mid 367.585871 -221.420777)
		(end 367.663984 -221.14383)
		(width 0.0889)
		(layer "In6.Cu")
		(net "DMI_CPU0_PCH_TX_DN<2>")
	)
	(arc
		(start 366.917732 -222.433642)
		(mid 367.120145 -222.227229)
		(end 367.194084 -221.94774)
		(width 0.0889)
		(layer "In6.Cu")
		(net "DMI_CPU0_PCH_TX_DN<2>")
	)
	(arc
		(start 365.971836 -225.69297)
		(mid 366.173118 -225.495483)
		(end 366.25403 -225.225356)
		(width 0.0889)
		(layer "In6.Cu")
		(net "DMI_CPU0_PCH_TX_DN<2>")
	)
	(arc
		(start 364.844584 -226.017328)
		(mid 364.844636 -226.009961)
		(end 364.844838 -226.002596)
		(width 0.0889)
		(layer "In6.Cu")
		(net "DMI_CPU0_PCH_TX_DN<2>")
	)
	(arc
		(start 363.622336 -226.506786)
		(mid 363.809534 -226.456643)
		(end 363.996732 -226.506786)
		(width 0.0889)
		(layer "In6.Cu")
		(net "DMI_CPU0_PCH_TX_DN<2>")
	)
	(arc
		(start 366.25403 -225.187764)
		(mid 366.17466 -224.91403)
		(end 365.971836 -224.7138)
		(width 0.0889)
		(layer "In6.Cu")
		(net "DMI_CPU0_PCH_TX_DN<2>")
	)
	(arc
		(start 366.724184 -222.761556)
		(mid 366.771863 -222.578656)
		(end 366.902746 -222.442278)
		(width 0.0889)
		(layer "In6.Cu")
		(net "DMI_CPU0_PCH_TX_DN<2>")
	)
	(arc
		(start 362.21289 -227.320602)
		(mid 362.415713 -227.120371)
		(end 362.495084 -226.846638)
		(width 0.0889)
		(layer "In6.Cu")
		(net "DMI_CPU0_PCH_TX_DN<2>")
	)
	(arc
		(start 367.381536 -219.995496)
		(mid 367.585871 -219.792891)
		(end 367.663984 -219.515944)
		(width 0.0889)
		(layer "In6.Cu")
		(net "DMI_CPU0_PCH_TX_DN<2>")
	)
	(arc
		(start 366.441482 -223.251268)
		(mid 366.644963 -223.050464)
		(end 366.724184 -222.77578)
		(width 0.0889)
		(layer "In6.Cu")
		(net "DMI_CPU0_PCH_TX_DN<2>")
	)
	(arc
		(start 367.851436 -219.18168)
		(mid 368.054259 -218.981449)
		(end 368.13363 -218.707716)
		(width 0.0889)
		(layer "In6.Cu")
		(net "DMI_CPU0_PCH_TX_DN<2>")
	)
	(arc
		(start 362.682536 -226.506786)
		(mid 362.869734 -226.456643)
		(end 363.056932 -226.506786)
		(width 0.0889)
		(layer "In6.Cu")
		(net "DMI_CPU0_PCH_TX_DN<2>")
	)
	(arc
		(start 364.844838 -226.002596)
		(mid 364.895892 -225.828016)
		(end 365.023146 -225.69805)
		(width 0.0889)
		(layer "In6.Cu")
		(net "DMI_CPU0_PCH_TX_DN<2>")
	)
	(arc
		(start 367.663984 -219.506038)
		(mid 367.711663 -219.323138)
		(end 367.842546 -219.18676)
		(width 0.0889)
		(layer "In6.Cu")
		(net "DMI_CPU0_PCH_TX_DN<2>")
	)
	(arc
		(start 366.254284 -223.56699)
		(mid 366.306554 -223.384625)
		(end 366.441482 -223.251268)
		(width 0.0889)
		(layer "In6.Cu")
		(net "DMI_CPU0_PCH_TX_DN<2>")
	)
	(arc
		(start 365.971836 -224.065084)
		(mid 366.176171 -223.862479)
		(end 366.254284 -223.585532)
		(width 0.0889)
		(layer "In6.Cu")
		(net "DMI_CPU0_PCH_TX_DN<2>")
	)
	(arc
		(start 368.603784 -216.25052)
		(mid 368.651463 -216.06762)
		(end 368.782346 -215.931242)
		(width 0.0889)
		(layer "In6.Cu")
		(net "DMI_CPU0_PCH_TX_DN<2>")
	)
	(arc
		(start 368.603784 -217.864182)
		(mid 368.524565 -217.589497)
		(end 368.321082 -217.388694)
		(width 0.0889)
		(layer "In6.Cu")
		(net "DMI_CPU0_PCH_TX_DN<2>")
	)
	(segment
		(start 360.51998 -228.1809)
		(end 360.520234 -228.180646)
		(width 0.13208)
		(layer "F.Cu")
		(net "DMI_CPU0_PCH_TX_DN<1>")
	)
	(segment
		(start 360.520234 -228.180646)
		(end 360.520234 -227.64496)
		(width 0.13208)
		(layer "F.Cu")
		(net "DMI_CPU0_PCH_TX_DN<1>")
	)
	(segment
		(start 345.090496 -72.299576)
		(end 344.800936 -72.010016)
		(width 0.13208)
		(layer "F.Cu")
		(net "DMI_CPU0_PCH_TX_DN<1>")
	)
	(segment
		(start 344.32113 -71.292974)
		(end 344.32113 -71.11492)
		(width 0.13208)
		(layer "F.Cu")
		(net "DMI_CPU0_PCH_TX_DN<1>")
	)
	(segment
		(start 344.800936 -72.010016)
		(end 344.800936 -71.77278)
		(width 0.13208)
		(layer "F.Cu")
		(net "DMI_CPU0_PCH_TX_DN<1>")
	)
	(segment
		(start 344.800936 -71.77278)
		(end 344.32113 -71.292974)
		(width 0.13208)
		(layer "F.Cu")
		(net "DMI_CPU0_PCH_TX_DN<1>")
	)
	(segment
		(start 344.32113 -71.11492)
		(end 344.64879 -70.78726)
		(width 0.13208)
		(layer "F.Cu")
		(net "DMI_CPU0_PCH_TX_DN<1>")
	)
	(segment
		(start 347.41358 -81.47812)
		(end 344.795856 -73.6219)
		(width 0.14732)
		(layer "In6.Cu")
		(net "DMI_CPU0_PCH_TX_DN<1>")
	)
	(segment
		(start 366.902746 -219.18676)
		(end 366.911636 -219.18168)
		(width 0.0889)
		(layer "In6.Cu")
		(net "DMI_CPU0_PCH_TX_DN<1>")
	)
	(segment
		(start 367.663984 -217.878406)
		(end 367.663984 -217.859864)
		(width 0.0889)
		(layer "In6.Cu")
		(net "DMI_CPU0_PCH_TX_DN<1>")
	)
	(segment
		(start 366.254284 -220.32849)
		(end 366.254284 -220.311218)
		(width 0.0889)
		(layer "In6.Cu")
		(net "DMI_CPU0_PCH_TX_DN<1>")
	)
	(segment
		(start 364.37443 -225.225356)
		(end 364.37443 -225.203258)
		(width 0.0889)
		(layer "In6.Cu")
		(net "DMI_CPU0_PCH_TX_DN<1>")
	)
	(segment
		(start 369.095782 -209.370168)
		(end 369.440968 -207.412082)
		(width 0.14732)
		(layer "In6.Cu")
		(net "DMI_CPU0_PCH_TX_DN<1>")
	)
	(segment
		(start 369.053872 -214.40648)
		(end 369.053872 -211.759038)
		(width 0.0889)
		(layer "In6.Cu")
		(net "DMI_CPU0_PCH_TX_DN<1>")
	)
	(segment
		(start 366.441482 -219.995496)
		(end 366.442244 -219.994988)
		(width 0.0889)
		(layer "In6.Cu")
		(net "DMI_CPU0_PCH_TX_DN<1>")
	)
	(segment
		(start 366.25403 -221.963234)
		(end 366.25403 -221.94774)
		(width 0.0889)
		(layer "In6.Cu")
		(net "DMI_CPU0_PCH_TX_DN<1>")
	)
	(segment
		(start 366.724184 -221.133924)
		(end 366.724184 -221.1197)
		(width 0.0889)
		(layer "In6.Cu")
		(net "DMI_CPU0_PCH_TX_DN<1>")
	)
	(segment
		(start 374.518174 -200.161398)
		(end 379.014228 -197.013322)
		(width 0.14732)
		(layer "In6.Cu")
		(net "DMI_CPU0_PCH_TX_DN<1>")
	)
	(segment
		(start 368.321082 -215.112346)
		(end 368.320828 -215.112092)
		(width 0.0889)
		(layer "In6.Cu")
		(net "DMI_CPU0_PCH_TX_DN<1>")
	)
	(segment
		(start 360.676698 -227.373942)
		(end 360.765598 -227.35032)
		(width 0.0889)
		(layer "In6.Cu")
		(net "DMI_CPU0_PCH_TX_DN<1>")
	)
	(segment
		(start 366.441482 -221.623382)
		(end 366.447578 -221.619826)
		(width 0.0889)
		(layer "In6.Cu")
		(net "DMI_CPU0_PCH_TX_DN<1>")
	)
	(segment
		(start 380.781814 -195.245736)
		(end 385.256532 -188.855096)
		(width 0.14732)
		(layer "In6.Cu")
		(net "DMI_CPU0_PCH_TX_DN<1>")
	)
	(segment
		(start 367.19383 -218.707716)
		(end 367.19383 -218.692222)
		(width 0.0889)
		(layer "In6.Cu")
		(net "DMI_CPU0_PCH_TX_DN<1>")
	)
	(segment
		(start 379.014228 -197.013322)
		(end 380.781814 -195.245736)
		(width 0.14732)
		(layer "In6.Cu")
		(net "DMI_CPU0_PCH_TX_DN<1>")
	)
	(segment
		(start 344.795856 -72.594216)
		(end 345.090496 -72.299576)
		(width 0.14732)
		(layer "In6.Cu")
		(net "DMI_CPU0_PCH_TX_DN<1>")
	)
	(segment
		(start 369.053872 -211.759038)
		(end 369.095782 -211.717128)
		(width 0.0889)
		(layer "In6.Cu")
		(net "DMI_CPU0_PCH_TX_DN<1>")
	)
	(segment
		(start 344.795856 -73.6219)
		(end 344.795856 -72.594216)
		(width 0.14732)
		(layer "In6.Cu")
		(net "DMI_CPU0_PCH_TX_DN<1>")
	)
	(segment
		(start 381.985012 -148.819362)
		(end 347.41358 -81.47812)
		(width 0.14732)
		(layer "In6.Cu")
		(net "DMI_CPU0_PCH_TX_DN<1>")
	)
	(segment
		(start 369.440968 -207.412082)
		(end 374.518174 -200.161398)
		(width 0.14732)
		(layer "In6.Cu")
		(net "DMI_CPU0_PCH_TX_DN<1>")
	)
	(segment
		(start 366.432592 -221.628462)
		(end 366.441482 -221.623382)
		(width 0.0889)
		(layer "In6.Cu")
		(net "DMI_CPU0_PCH_TX_DN<1>")
	)
	(segment
		(start 364.561882 -224.8789)
		(end 364.567978 -224.875344)
		(width 0.0889)
		(layer "In6.Cu")
		(net "DMI_CPU0_PCH_TX_DN<1>")
	)
	(segment
		(start 365.962946 -222.442278)
		(end 365.971836 -222.437198)
		(width 0.0889)
		(layer "In6.Cu")
		(net "DMI_CPU0_PCH_TX_DN<1>")
	)
	(segment
		(start 366.445038 -219.993464)
		(end 366.447578 -219.99194)
		(width 0.0889)
		(layer "In6.Cu")
		(net "DMI_CPU0_PCH_TX_DN<1>")
	)
	(segment
		(start 369.095782 -211.69503)
		(end 369.095782 -209.370168)
		(width 0.14732)
		(layer "In6.Cu")
		(net "DMI_CPU0_PCH_TX_DN<1>")
	)
	(segment
		(start 365.032036 -224.065084)
		(end 365.038132 -224.061528)
		(width 0.0889)
		(layer "In6.Cu")
		(net "DMI_CPU0_PCH_TX_DN<1>")
	)
	(segment
		(start 362.025184 -226.027234)
		(end 362.025184 -226.017328)
		(width 0.0889)
		(layer "In6.Cu")
		(net "DMI_CPU0_PCH_TX_DN<1>")
	)
	(segment
		(start 361.741974 -226.507294)
		(end 361.742736 -226.506786)
		(width 0.0889)
		(layer "In6.Cu")
		(net "DMI_CPU0_PCH_TX_DN<1>")
	)
	(segment
		(start 367.663984 -216.260426)
		(end 367.663984 -216.25052)
		(width 0.0889)
		(layer "In6.Cu")
		(net "DMI_CPU0_PCH_TX_DN<1>")
	)
	(segment
		(start 365.023146 -224.070164)
		(end 365.032036 -224.065084)
		(width 0.0889)
		(layer "In6.Cu")
		(net "DMI_CPU0_PCH_TX_DN<1>")
	)
	(segment
		(start 367.372646 -216.745058)
		(end 367.381536 -216.739978)
		(width 0.0889)
		(layer "In6.Cu")
		(net "DMI_CPU0_PCH_TX_DN<1>")
	)
	(segment
		(start 362.587032 -225.69297)
		(end 362.601764 -225.701606)
		(width 0.0889)
		(layer "In6.Cu")
		(net "DMI_CPU0_PCH_TX_DN<1>")
	)
	(segment
		(start 385.256532 -188.855096)
		(end 387.150356 -178.111658)
		(width 0.14732)
		(layer "In6.Cu")
		(net "DMI_CPU0_PCH_TX_DN<1>")
	)
	(segment
		(start 366.442244 -219.994988)
		(end 366.445038 -219.993464)
		(width 0.0889)
		(layer "In6.Cu")
		(net "DMI_CPU0_PCH_TX_DN<1>")
	)
	(segment
		(start 367.372392 -218.372944)
		(end 367.381282 -218.367864)
		(width 0.0889)
		(layer "In6.Cu")
		(net "DMI_CPU0_PCH_TX_DN<1>")
	)
	(segment
		(start 365.493046 -223.256348)
		(end 365.501936 -223.251268)
		(width 0.0889)
		(layer "In6.Cu")
		(net "DMI_CPU0_PCH_TX_DN<1>")
	)
	(segment
		(start 361.272836 -227.320602)
		(end 361.278932 -227.317046)
		(width 0.0889)
		(layer "In6.Cu")
		(net "DMI_CPU0_PCH_TX_DN<1>")
	)
	(segment
		(start 368.438176 -215.022176)
		(end 369.053872 -214.40648)
		(width 0.0889)
		(layer "In6.Cu")
		(net "DMI_CPU0_PCH_TX_DN<1>")
	)
	(segment
		(start 362.203746 -225.69805)
		(end 362.212636 -225.69297)
		(width 0.0889)
		(layer "In6.Cu")
		(net "DMI_CPU0_PCH_TX_DN<1>")
	)
	(segment
		(start 367.842546 -215.931242)
		(end 367.851436 -215.926162)
		(width 0.0889)
		(layer "In6.Cu")
		(net "DMI_CPU0_PCH_TX_DN<1>")
	)
	(segment
		(start 364.552992 -224.88398)
		(end 364.561882 -224.8789)
		(width 0.0889)
		(layer "In6.Cu")
		(net "DMI_CPU0_PCH_TX_DN<1>")
	)
	(segment
		(start 360.520234 -227.64496)
		(end 360.676698 -227.373942)
		(width 0.0889)
		(layer "In6.Cu")
		(net "DMI_CPU0_PCH_TX_DN<1>")
	)
	(segment
		(start 367.381282 -218.367864)
		(end 367.387378 -218.364308)
		(width 0.0889)
		(layer "In6.Cu")
		(net "DMI_CPU0_PCH_TX_DN<1>")
	)
	(segment
		(start 361.733846 -226.511866)
		(end 361.741974 -226.507294)
		(width 0.0889)
		(layer "In6.Cu")
		(net "DMI_CPU0_PCH_TX_DN<1>")
	)
	(segment
		(start 368.133884 -215.44661)
		(end 368.133884 -215.428068)
		(width 0.0889)
		(layer "In6.Cu")
		(net "DMI_CPU0_PCH_TX_DN<1>")
	)
	(segment
		(start 367.381536 -217.388694)
		(end 367.372646 -217.383614)
		(width 0.0889)
		(layer "In6.Cu")
		(net "DMI_CPU0_PCH_TX_DN<1>")
	)
	(segment
		(start 365.784384 -222.780098)
		(end 365.784384 -222.761556)
		(width 0.0889)
		(layer "In6.Cu")
		(net "DMI_CPU0_PCH_TX_DN<1>")
	)
	(segment
		(start 387.150356 -178.111658)
		(end 381.985012 -148.819362)
		(width 0.14732)
		(layer "In6.Cu")
		(net "DMI_CPU0_PCH_TX_DN<1>")
	)
	(segment
		(start 363.526832 -225.69297)
		(end 363.541564 -225.701606)
		(width 0.0889)
		(layer "In6.Cu")
		(net "DMI_CPU0_PCH_TX_DN<1>")
	)
	(segment
		(start 369.095782 -211.717128)
		(end 369.095782 -211.69503)
		(width 0.0889)
		(layer "In6.Cu")
		(net "DMI_CPU0_PCH_TX_DN<1>")
	)
	(arc
		(start 362.025184 -226.017328)
		(mid 362.025236 -226.009961)
		(end 362.025438 -226.002596)
		(width 0.0889)
		(layer "In6.Cu")
		(net "DMI_CPU0_PCH_TX_DN<1>")
	)
	(arc
		(start 367.372646 -217.383614)
		(mid 367.194049 -217.064336)
		(end 367.372646 -216.745058)
		(width 0.0889)
		(layer "In6.Cu")
		(net "DMI_CPU0_PCH_TX_DN<1>")
	)
	(arc
		(start 367.851436 -215.926162)
		(mid 368.055771 -215.723557)
		(end 368.133884 -215.44661)
		(width 0.0889)
		(layer "In6.Cu")
		(net "DMI_CPU0_PCH_TX_DN<1>")
	)
	(arc
		(start 368.320828 -215.112092)
		(mid 368.382467 -215.071002)
		(end 368.438176 -215.022176)
		(width 0.0889)
		(layer "In6.Cu")
		(net "DMI_CPU0_PCH_TX_DN<1>")
	)
	(arc
		(start 363.541564 -225.701606)
		(mid 363.818005 -225.768772)
		(end 364.092236 -225.69297)
		(width 0.0889)
		(layer "In6.Cu")
		(net "DMI_CPU0_PCH_TX_DN<1>")
	)
	(arc
		(start 361.278932 -227.317046)
		(mid 361.481345 -227.110633)
		(end 361.555284 -226.831144)
		(width 0.0889)
		(layer "In6.Cu")
		(net "DMI_CPU0_PCH_TX_DN<1>")
	)
	(arc
		(start 364.844584 -224.389442)
		(mid 364.892263 -224.206542)
		(end 365.023146 -224.070164)
		(width 0.0889)
		(layer "In6.Cu")
		(net "DMI_CPU0_PCH_TX_DN<1>")
	)
	(arc
		(start 367.663984 -217.859864)
		(mid 367.583822 -217.587675)
		(end 367.381536 -217.388694)
		(width 0.0889)
		(layer "In6.Cu")
		(net "DMI_CPU0_PCH_TX_DN<1>")
	)
	(arc
		(start 365.784384 -222.761556)
		(mid 365.832063 -222.578656)
		(end 365.962946 -222.442278)
		(width 0.0889)
		(layer "In6.Cu")
		(net "DMI_CPU0_PCH_TX_DN<1>")
	)
	(arc
		(start 366.254284 -220.311218)
		(mid 366.306554 -220.128853)
		(end 366.441482 -219.995496)
		(width 0.0889)
		(layer "In6.Cu")
		(net "DMI_CPU0_PCH_TX_DN<1>")
	)
	(arc
		(start 364.567978 -224.875344)
		(mid 364.770565 -224.668993)
		(end 364.844584 -224.389442)
		(width 0.0889)
		(layer "In6.Cu")
		(net "DMI_CPU0_PCH_TX_DN<1>")
	)
	(arc
		(start 366.447578 -219.99194)
		(mid 366.650165 -219.785589)
		(end 366.724184 -219.506038)
		(width 0.0889)
		(layer "In6.Cu")
		(net "DMI_CPU0_PCH_TX_DN<1>")
	)
	(arc
		(start 362.025438 -226.002596)
		(mid 362.076492 -225.828016)
		(end 362.203746 -225.69805)
		(width 0.0889)
		(layer "In6.Cu")
		(net "DMI_CPU0_PCH_TX_DN<1>")
	)
	(arc
		(start 366.911636 -219.18168)
		(mid 367.114459 -218.981449)
		(end 367.19383 -218.707716)
		(width 0.0889)
		(layer "In6.Cu")
		(net "DMI_CPU0_PCH_TX_DN<1>")
	)
	(arc
		(start 364.37443 -225.203258)
		(mid 364.422109 -225.020358)
		(end 364.552992 -224.88398)
		(width 0.0889)
		(layer "In6.Cu")
		(net "DMI_CPU0_PCH_TX_DN<1>")
	)
	(arc
		(start 366.25403 -221.94774)
		(mid 366.301709 -221.76484)
		(end 366.432592 -221.628462)
		(width 0.0889)
		(layer "In6.Cu")
		(net "DMI_CPU0_PCH_TX_DN<1>")
	)
	(arc
		(start 363.152436 -225.69297)
		(mid 363.339634 -225.642827)
		(end 363.526832 -225.69297)
		(width 0.0889)
		(layer "In6.Cu")
		(net "DMI_CPU0_PCH_TX_DN<1>")
	)
	(arc
		(start 360.78541 -227.358448)
		(mid 361.033421 -227.394913)
		(end 361.272836 -227.320602)
		(width 0.0889)
		(layer "In6.Cu")
		(net "DMI_CPU0_PCH_TX_DN<1>")
	)
	(arc
		(start 367.19383 -218.692222)
		(mid 367.241509 -218.509322)
		(end 367.372392 -218.372944)
		(width 0.0889)
		(layer "In6.Cu")
		(net "DMI_CPU0_PCH_TX_DN<1>")
	)
	(arc
		(start 365.314484 -223.575626)
		(mid 365.362163 -223.392726)
		(end 365.493046 -223.256348)
		(width 0.0889)
		(layer "In6.Cu")
		(net "DMI_CPU0_PCH_TX_DN<1>")
	)
	(arc
		(start 368.133884 -215.428068)
		(mid 368.186154 -215.245703)
		(end 368.321082 -215.112346)
		(width 0.0889)
		(layer "In6.Cu")
		(net "DMI_CPU0_PCH_TX_DN<1>")
	)
	(arc
		(start 367.663984 -216.25052)
		(mid 367.711663 -216.06762)
		(end 367.842546 -215.931242)
		(width 0.0889)
		(layer "In6.Cu")
		(net "DMI_CPU0_PCH_TX_DN<1>")
	)
	(arc
		(start 362.601764 -225.701606)
		(mid 362.878205 -225.768772)
		(end 363.152436 -225.69297)
		(width 0.0889)
		(layer "In6.Cu")
		(net "DMI_CPU0_PCH_TX_DN<1>")
	)
	(arc
		(start 366.447578 -221.619826)
		(mid 366.650165 -221.413475)
		(end 366.724184 -221.133924)
		(width 0.0889)
		(layer "In6.Cu")
		(net "DMI_CPU0_PCH_TX_DN<1>")
	)
	(arc
		(start 367.381536 -216.739978)
		(mid 367.585871 -216.537373)
		(end 367.663984 -216.260426)
		(width 0.0889)
		(layer "In6.Cu")
		(net "DMI_CPU0_PCH_TX_DN<1>")
	)
	(arc
		(start 367.387378 -218.364308)
		(mid 367.589965 -218.157957)
		(end 367.663984 -217.878406)
		(width 0.0889)
		(layer "In6.Cu")
		(net "DMI_CPU0_PCH_TX_DN<1>")
	)
	(arc
		(start 366.724184 -221.1197)
		(mid 366.644965 -220.845015)
		(end 366.441482 -220.644212)
		(width 0.0889)
		(layer "In6.Cu")
		(net "DMI_CPU0_PCH_TX_DN<1>")
	)
	(arc
		(start 365.971836 -222.437198)
		(mid 366.174659 -222.236967)
		(end 366.25403 -221.963234)
		(width 0.0889)
		(layer "In6.Cu")
		(net "DMI_CPU0_PCH_TX_DN<1>")
	)
	(arc
		(start 366.441482 -220.644212)
		(mid 366.306549 -220.510858)
		(end 366.254284 -220.32849)
		(width 0.0889)
		(layer "In6.Cu")
		(net "DMI_CPU0_PCH_TX_DN<1>")
	)
	(arc
		(start 364.092236 -225.69297)
		(mid 364.293518 -225.495483)
		(end 364.37443 -225.225356)
		(width 0.0889)
		(layer "In6.Cu")
		(net "DMI_CPU0_PCH_TX_DN<1>")
	)
	(arc
		(start 362.212636 -225.69297)
		(mid 362.399834 -225.642827)
		(end 362.587032 -225.69297)
		(width 0.0889)
		(layer "In6.Cu")
		(net "DMI_CPU0_PCH_TX_DN<1>")
	)
	(arc
		(start 366.724184 -219.506038)
		(mid 366.771863 -219.323138)
		(end 366.902746 -219.18676)
		(width 0.0889)
		(layer "In6.Cu")
		(net "DMI_CPU0_PCH_TX_DN<1>")
	)
	(arc
		(start 365.038132 -224.061528)
		(mid 365.240545 -223.855115)
		(end 365.314484 -223.575626)
		(width 0.0889)
		(layer "In6.Cu")
		(net "DMI_CPU0_PCH_TX_DN<1>")
	)
	(arc
		(start 360.765598 -227.35032)
		(mid 360.775465 -227.354479)
		(end 360.78541 -227.358448)
		(width 0.0889)
		(layer "In6.Cu")
		(net "DMI_CPU0_PCH_TX_DN<1>")
	)
	(arc
		(start 361.555284 -226.831144)
		(mid 361.602963 -226.648244)
		(end 361.733846 -226.511866)
		(width 0.0889)
		(layer "In6.Cu")
		(net "DMI_CPU0_PCH_TX_DN<1>")
	)
	(arc
		(start 361.742736 -226.506786)
		(mid 361.947071 -226.304181)
		(end 362.025184 -226.027234)
		(width 0.0889)
		(layer "In6.Cu")
		(net "DMI_CPU0_PCH_TX_DN<1>")
	)
	(arc
		(start 365.501936 -223.251268)
		(mid 365.704222 -223.052287)
		(end 365.784384 -222.780098)
		(width 0.0889)
		(layer "In6.Cu")
		(net "DMI_CPU0_PCH_TX_DN<1>")
	)
	(segment
		(start 342.43899 -70.30466)
		(end 342.111076 -70.632574)
		(width 0.13208)
		(layer "F.Cu")
		(net "DMI_CPU0_PCH_TX_DN<0>")
	)
	(segment
		(start 342.111076 -70.883526)
		(end 342.413336 -71.185786)
		(width 0.13208)
		(layer "F.Cu")
		(net "DMI_CPU0_PCH_TX_DN<0>")
	)
	(segment
		(start 360.98988 -228.994716)
		(end 360.98988 -228.45903)
		(width 0.13208)
		(layer "F.Cu")
		(net "DMI_CPU0_PCH_TX_DN<0>")
	)
	(segment
		(start 342.111076 -70.632574)
		(end 342.111076 -70.883526)
		(width 0.13208)
		(layer "F.Cu")
		(net "DMI_CPU0_PCH_TX_DN<0>")
	)
	(segment
		(start 360.990134 -228.99497)
		(end 360.98988 -228.994716)
		(width 0.13208)
		(layer "F.Cu")
		(net "DMI_CPU0_PCH_TX_DN<0>")
	)
	(segment
		(start 365.492792 -221.628462)
		(end 365.500158 -221.624144)
		(width 0.0889)
		(layer "In6.Cu")
		(net "DMI_CPU0_PCH_TX_DN<0>")
	)
	(segment
		(start 365.023146 -222.442278)
		(end 365.032036 -222.437198)
		(width 0.0889)
		(layer "In6.Cu")
		(net "DMI_CPU0_PCH_TX_DN<0>")
	)
	(segment
		(start 380.052072 -194.763136)
		(end 384.20675 -188.82995)
		(width 0.14732)
		(layer "In6.Cu")
		(net "DMI_CPU0_PCH_TX_DN<0>")
	)
	(segment
		(start 343.182448 -75.27163)
		(end 343.028524 -74.862944)
		(width 0.14732)
		(layer "In6.Cu")
		(net "DMI_CPU0_PCH_TX_DN<0>")
	)
	(segment
		(start 342.394286 -73.179686)
		(end 342.119966 -72.45096)
		(width 0.14732)
		(layer "In6.Cu")
		(net "DMI_CPU0_PCH_TX_DN<0>")
	)
	(segment
		(start 367.380774 -215.112854)
		(end 367.38052 -215.112092)
		(width 0.0889)
		(layer "In6.Cu")
		(net "DMI_CPU0_PCH_TX_DN<0>")
	)
	(segment
		(start 361.263946 -224.070164)
		(end 361.272836 -224.065084)
		(width 0.0889)
		(layer "In6.Cu")
		(net "DMI_CPU0_PCH_TX_DN<0>")
	)
	(segment
		(start 361.55503 -225.225356)
		(end 361.55503 -225.187764)
		(width 0.0889)
		(layer "In6.Cu")
		(net "DMI_CPU0_PCH_TX_DN<0>")
	)
	(segment
		(start 363.613446 -223.256348)
		(end 363.622336 -223.251268)
		(width 0.0889)
		(layer "In6.Cu")
		(net "DMI_CPU0_PCH_TX_DN<0>")
	)
	(segment
		(start 386.16255 -177.735992)
		(end 381.093218 -148.991574)
		(width 0.14732)
		(layer "In6.Cu")
		(net "DMI_CPU0_PCH_TX_DN<0>")
	)
	(segment
		(start 363.434884 -223.585532)
		(end 363.434884 -223.575626)
		(width 0.0889)
		(layer "In6.Cu")
		(net "DMI_CPU0_PCH_TX_DN<0>")
	)
	(segment
		(start 361.272836 -224.7138)
		(end 361.263946 -224.70872)
		(width 0.0889)
		(layer "In6.Cu")
		(net "DMI_CPU0_PCH_TX_DN<0>")
	)
	(segment
		(start 362.66755 -224.887536)
		(end 362.688378 -224.875344)
		(width 0.0889)
		(layer "In6.Cu")
		(net "DMI_CPU0_PCH_TX_DN<0>")
	)
	(segment
		(start 360.802682 -226.506786)
		(end 360.803444 -226.506278)
		(width 0.0889)
		(layer "In6.Cu")
		(net "DMI_CPU0_PCH_TX_DN<0>")
	)
	(segment
		(start 342.118696 -72.451468)
		(end 342.118696 -71.480426)
		(width 0.14732)
		(layer "In6.Cu")
		(net "DMI_CPU0_PCH_TX_DN<0>")
	)
	(segment
		(start 366.432592 -218.372944)
		(end 366.441482 -218.367864)
		(width 0.0889)
		(layer "In6.Cu")
		(net "DMI_CPU0_PCH_TX_DN<0>")
	)
	(segment
		(start 343.099644 -74.705972)
		(end 342.94572 -74.296778)
		(width 0.14732)
		(layer "In6.Cu")
		(net "DMI_CPU0_PCH_TX_DN<0>")
	)
	(segment
		(start 365.501936 -220.644212)
		(end 365.493046 -220.639132)
		(width 0.0889)
		(layer "In6.Cu")
		(net "DMI_CPU0_PCH_TX_DN<0>")
	)
	(segment
		(start 342.118696 -71.480426)
		(end 342.413336 -71.185786)
		(width 0.14732)
		(layer "In6.Cu")
		(net "DMI_CPU0_PCH_TX_DN<0>")
	)
	(segment
		(start 365.501682 -221.623382)
		(end 365.502444 -221.622874)
		(width 0.0889)
		(layer "In6.Cu")
		(net "DMI_CPU0_PCH_TX_DN<0>")
	)
	(segment
		(start 360.333036 -227.969318)
		(end 360.324146 -227.964238)
		(width 0.0889)
		(layer "In6.Cu")
		(net "DMI_CPU0_PCH_TX_DN<0>")
	)
	(segment
		(start 364.844584 -222.77578)
		(end 364.844584 -222.761556)
		(width 0.0889)
		(layer "In6.Cu")
		(net "DMI_CPU0_PCH_TX_DN<0>")
	)
	(segment
		(start 365.962946 -219.18676)
		(end 365.971836 -219.18168)
		(width 0.0889)
		(layer "In6.Cu")
		(net "DMI_CPU0_PCH_TX_DN<0>")
	)
	(segment
		(start 348.911164 -88.387428)
		(end 343.182448 -75.27163)
		(width 0.14732)
		(layer "In6.Cu")
		(net "DMI_CPU0_PCH_TX_DN<0>")
	)
	(segment
		(start 342.63457 -73.816972)
		(end 342.70569 -73.66)
		(width 0.14732)
		(layer "In6.Cu")
		(net "DMI_CPU0_PCH_TX_DN<0>")
	)
	(segment
		(start 365.31423 -221.963234)
		(end 365.31423 -221.94774)
		(width 0.0889)
		(layer "In6.Cu")
		(net "DMI_CPU0_PCH_TX_DN<0>")
	)
	(segment
		(start 367.19383 -215.452198)
		(end 367.19383 -215.436704)
		(width 0.0889)
		(layer "In6.Cu")
		(net "DMI_CPU0_PCH_TX_DN<0>")
	)
	(segment
		(start 342.119204 -72.45096)
		(end 342.118696 -72.451468)
		(width 0.14732)
		(layer "In6.Cu")
		(net "DMI_CPU0_PCH_TX_DN<0>")
	)
	(segment
		(start 368.146584 -214.37346)
		(end 368.146584 -211.345018)
		(width 0.0889)
		(layer "In6.Cu")
		(net "DMI_CPU0_PCH_TX_DN<0>")
	)
	(segment
		(start 360.98988 -228.45903)
		(end 360.677206 -228.45903)
		(width 0.0889)
		(layer "In6.Cu")
		(net "DMI_CPU0_PCH_TX_DN<0>")
	)
	(segment
		(start 364.551468 -223.257364)
		(end 364.561882 -223.251268)
		(width 0.0889)
		(layer "In6.Cu")
		(net "DMI_CPU0_PCH_TX_DN<0>")
	)
	(segment
		(start 343.028524 -74.862944)
		(end 343.099644 -74.705972)
		(width 0.14732)
		(layer "In6.Cu")
		(net "DMI_CPU0_PCH_TX_DN<0>")
	)
	(segment
		(start 366.441482 -216.739978)
		(end 366.442244 -216.73947)
		(width 0.0889)
		(layer "In6.Cu")
		(net "DMI_CPU0_PCH_TX_DN<0>")
	)
	(segment
		(start 361.647232 -224.065084)
		(end 361.656122 -224.070164)
		(width 0.0889)
		(layer "In6.Cu")
		(net "DMI_CPU0_PCH_TX_DN<0>")
	)
	(segment
		(start 342.94572 -74.296778)
		(end 342.788494 -74.225658)
		(width 0.14732)
		(layer "In6.Cu")
		(net "DMI_CPU0_PCH_TX_DN<0>")
	)
	(segment
		(start 363.143546 -224.070164)
		(end 363.152436 -224.065084)
		(width 0.0889)
		(layer "In6.Cu")
		(net "DMI_CPU0_PCH_TX_DN<0>")
	)
	(segment
		(start 342.551766 -73.250806)
		(end 342.394286 -73.179686)
		(width 0.14732)
		(layer "In6.Cu")
		(net "DMI_CPU0_PCH_TX_DN<0>")
	)
	(segment
		(start 366.25403 -218.707716)
		(end 366.25403 -218.692222)
		(width 0.0889)
		(layer "In6.Cu")
		(net "DMI_CPU0_PCH_TX_DN<0>")
	)
	(segment
		(start 365.501174 -219.996004)
		(end 365.501936 -219.995496)
		(width 0.0889)
		(layer "In6.Cu")
		(net "DMI_CPU0_PCH_TX_DN<0>")
	)
	(segment
		(start 365.500158 -221.624144)
		(end 365.501682 -221.623382)
		(width 0.0889)
		(layer "In6.Cu")
		(net "DMI_CPU0_PCH_TX_DN<0>")
	)
	(segment
		(start 360.803444 -226.506278)
		(end 360.806238 -226.504754)
		(width 0.0889)
		(layer "In6.Cu")
		(net "DMI_CPU0_PCH_TX_DN<0>")
	)
	(segment
		(start 366.724184 -217.878406)
		(end 366.724184 -217.864182)
		(width 0.0889)
		(layer "In6.Cu")
		(net "DMI_CPU0_PCH_TX_DN<0>")
	)
	(segment
		(start 365.784384 -221.133924)
		(end 365.784384 -221.115382)
		(width 0.0889)
		(layer "In6.Cu")
		(net "DMI_CPU0_PCH_TX_DN<0>")
	)
	(segment
		(start 368.188494 -209.290412)
		(end 368.553746 -207.216756)
		(width 0.14732)
		(layer "In6.Cu")
		(net "DMI_CPU0_PCH_TX_DN<0>")
	)
	(segment
		(start 381.093218 -148.991574)
		(end 348.911164 -88.387428)
		(width 0.14732)
		(layer "In6.Cu")
		(net "DMI_CPU0_PCH_TX_DN<0>")
	)
	(segment
		(start 360.324146 -227.325682)
		(end 360.333036 -227.320602)
		(width 0.0889)
		(layer "In6.Cu")
		(net "DMI_CPU0_PCH_TX_DN<0>")
	)
	(segment
		(start 360.806238 -226.504754)
		(end 360.808778 -226.50323)
		(width 0.0889)
		(layer "In6.Cu")
		(net "DMI_CPU0_PCH_TX_DN<0>")
	)
	(segment
		(start 367.372392 -215.117426)
		(end 367.380774 -215.112854)
		(width 0.0889)
		(layer "In6.Cu")
		(net "DMI_CPU0_PCH_TX_DN<0>")
	)
	(segment
		(start 342.70569 -73.66)
		(end 342.551766 -73.250806)
		(width 0.14732)
		(layer "In6.Cu")
		(net "DMI_CPU0_PCH_TX_DN<0>")
	)
	(segment
		(start 368.553746 -207.216756)
		(end 373.94896 -199.51192)
		(width 0.14732)
		(layer "In6.Cu")
		(net "DMI_CPU0_PCH_TX_DN<0>")
	)
	(segment
		(start 360.677206 -228.45903)
		(end 360.611928 -228.393752)
		(width 0.0889)
		(layer "In6.Cu")
		(net "DMI_CPU0_PCH_TX_DN<0>")
	)
	(segment
		(start 378.466096 -196.349112)
		(end 380.052072 -194.763136)
		(width 0.14732)
		(layer "In6.Cu")
		(net "DMI_CPU0_PCH_TX_DN<0>")
	)
	(segment
		(start 342.788494 -74.225658)
		(end 342.63457 -73.816972)
		(width 0.14732)
		(layer "In6.Cu")
		(net "DMI_CPU0_PCH_TX_DN<0>")
	)
	(segment
		(start 367.497614 -215.02243)
		(end 368.146584 -214.37346)
		(width 0.0889)
		(layer "In6.Cu")
		(net "DMI_CPU0_PCH_TX_DN<0>")
	)
	(segment
		(start 368.188494 -211.28101)
		(end 368.188494 -209.290412)
		(width 0.14732)
		(layer "In6.Cu")
		(net "DMI_CPU0_PCH_TX_DN<0>")
	)
	(segment
		(start 366.441482 -218.367864)
		(end 366.447578 -218.364308)
		(width 0.0889)
		(layer "In6.Cu")
		(net "DMI_CPU0_PCH_TX_DN<0>")
	)
	(segment
		(start 361.834684 -224.389442)
		(end 361.834684 -224.404936)
		(width 0.0889)
		(layer "In6.Cu")
		(net "DMI_CPU0_PCH_TX_DN<0>")
	)
	(segment
		(start 366.902746 -215.931242)
		(end 366.911636 -215.926162)
		(width 0.0889)
		(layer "In6.Cu")
		(net "DMI_CPU0_PCH_TX_DN<0>")
	)
	(segment
		(start 365.784384 -219.515944)
		(end 365.784384 -219.506038)
		(width 0.0889)
		(layer "In6.Cu")
		(net "DMI_CPU0_PCH_TX_DN<0>")
	)
	(segment
		(start 368.188494 -211.303108)
		(end 368.188494 -211.28101)
		(width 0.0889)
		(layer "In6.Cu")
		(net "DMI_CPU0_PCH_TX_DN<0>")
	)
	(segment
		(start 366.254284 -217.072972)
		(end 366.254284 -217.0557)
		(width 0.0889)
		(layer "In6.Cu")
		(net "DMI_CPU0_PCH_TX_DN<0>")
	)
	(segment
		(start 361.263946 -225.69805)
		(end 361.272836 -225.69297)
		(width 0.0889)
		(layer "In6.Cu")
		(net "DMI_CPU0_PCH_TX_DN<0>")
	)
	(segment
		(start 360.615484 -226.84105)
		(end 360.615484 -226.822508)
		(width 0.0889)
		(layer "In6.Cu")
		(net "DMI_CPU0_PCH_TX_DN<0>")
	)
	(segment
		(start 365.493046 -220.000576)
		(end 365.501174 -219.996004)
		(width 0.0889)
		(layer "In6.Cu")
		(net "DMI_CPU0_PCH_TX_DN<0>")
	)
	(segment
		(start 342.119966 -72.45096)
		(end 342.119204 -72.45096)
		(width 0.14732)
		(layer "In6.Cu")
		(net "DMI_CPU0_PCH_TX_DN<0>")
	)
	(segment
		(start 373.94896 -199.51192)
		(end 378.466096 -196.349112)
		(width 0.14732)
		(layer "In6.Cu")
		(net "DMI_CPU0_PCH_TX_DN<0>")
	)
	(segment
		(start 384.20675 -188.82995)
		(end 386.16255 -177.735992)
		(width 0.14732)
		(layer "In6.Cu")
		(net "DMI_CPU0_PCH_TX_DN<0>")
	)
	(segment
		(start 368.146584 -211.345018)
		(end 368.188494 -211.303108)
		(width 0.0889)
		(layer "In6.Cu")
		(net "DMI_CPU0_PCH_TX_DN<0>")
	)
	(segment
		(start 365.502444 -221.622874)
		(end 365.507778 -221.619826)
		(width 0.0889)
		(layer "In6.Cu")
		(net "DMI_CPU0_PCH_TX_DN<0>")
	)
	(segment
		(start 366.445038 -216.737946)
		(end 366.447578 -216.736422)
		(width 0.0889)
		(layer "In6.Cu")
		(net "DMI_CPU0_PCH_TX_DN<0>")
	)
	(segment
		(start 366.442244 -216.73947)
		(end 366.445038 -216.737946)
		(width 0.0889)
		(layer "In6.Cu")
		(net "DMI_CPU0_PCH_TX_DN<0>")
	)
	(arc
		(start 365.784384 -221.115382)
		(mid 365.704222 -220.843193)
		(end 365.501936 -220.644212)
		(width 0.0889)
		(layer "In6.Cu")
		(net "DMI_CPU0_PCH_TX_DN<0>")
	)
	(arc
		(start 361.085384 -226.017328)
		(mid 361.085436 -226.009961)
		(end 361.085638 -226.002596)
		(width 0.0889)
		(layer "In6.Cu")
		(net "DMI_CPU0_PCH_TX_DN<0>")
	)
	(arc
		(start 361.272836 -225.69297)
		(mid 361.474118 -225.495483)
		(end 361.55503 -225.225356)
		(width 0.0889)
		(layer "In6.Cu")
		(net "DMI_CPU0_PCH_TX_DN<0>")
	)
	(arc
		(start 360.615484 -226.822508)
		(mid 360.667754 -226.640143)
		(end 360.802682 -226.506786)
		(width 0.0889)
		(layer "In6.Cu")
		(net "DMI_CPU0_PCH_TX_DN<0>")
	)
	(arc
		(start 360.145838 -227.659692)
		(mid 360.145641 -227.652327)
		(end 360.145584 -227.64496)
		(width 0.0889)
		(layer "In6.Cu")
		(net "DMI_CPU0_PCH_TX_DN<0>")
	)
	(arc
		(start 361.55503 -225.187764)
		(mid 361.47566 -224.91403)
		(end 361.272836 -224.7138)
		(width 0.0889)
		(layer "In6.Cu")
		(net "DMI_CPU0_PCH_TX_DN<0>")
	)
	(arc
		(start 364.844584 -222.761556)
		(mid 364.892263 -222.578656)
		(end 365.023146 -222.442278)
		(width 0.0889)
		(layer "In6.Cu")
		(net "DMI_CPU0_PCH_TX_DN<0>")
	)
	(arc
		(start 366.441482 -217.388694)
		(mid 366.306549 -217.25534)
		(end 366.254284 -217.072972)
		(width 0.0889)
		(layer "In6.Cu")
		(net "DMI_CPU0_PCH_TX_DN<0>")
	)
	(arc
		(start 365.032036 -222.437198)
		(mid 365.234859 -222.236967)
		(end 365.31423 -221.963234)
		(width 0.0889)
		(layer "In6.Cu")
		(net "DMI_CPU0_PCH_TX_DN<0>")
	)
	(arc
		(start 365.31423 -221.94774)
		(mid 365.361909 -221.76484)
		(end 365.492792 -221.628462)
		(width 0.0889)
		(layer "In6.Cu")
		(net "DMI_CPU0_PCH_TX_DN<0>")
	)
	(arc
		(start 366.724184 -217.864182)
		(mid 366.644965 -217.589497)
		(end 366.441482 -217.388694)
		(width 0.0889)
		(layer "In6.Cu")
		(net "DMI_CPU0_PCH_TX_DN<0>")
	)
	(arc
		(start 363.434884 -223.575626)
		(mid 363.482563 -223.392726)
		(end 363.613446 -223.256348)
		(width 0.0889)
		(layer "In6.Cu")
		(net "DMI_CPU0_PCH_TX_DN<0>")
	)
	(arc
		(start 366.447578 -218.364308)
		(mid 366.650165 -218.157957)
		(end 366.724184 -217.878406)
		(width 0.0889)
		(layer "In6.Cu")
		(net "DMI_CPU0_PCH_TX_DN<0>")
	)
	(arc
		(start 363.622336 -223.251268)
		(mid 363.809534 -223.201125)
		(end 363.996732 -223.251268)
		(width 0.0889)
		(layer "In6.Cu")
		(net "DMI_CPU0_PCH_TX_DN<0>")
	)
	(arc
		(start 366.911636 -215.926162)
		(mid 367.114459 -215.725931)
		(end 367.19383 -215.452198)
		(width 0.0889)
		(layer "In6.Cu")
		(net "DMI_CPU0_PCH_TX_DN<0>")
	)
	(arc
		(start 360.609134 -228.372416)
		(mid 360.516875 -228.139501)
		(end 360.333036 -227.969318)
		(width 0.0889)
		(layer "In6.Cu")
		(net "DMI_CPU0_PCH_TX_DN<0>")
	)
	(arc
		(start 365.501936 -219.995496)
		(mid 365.706271 -219.792891)
		(end 365.784384 -219.515944)
		(width 0.0889)
		(layer "In6.Cu")
		(net "DMI_CPU0_PCH_TX_DN<0>")
	)
	(arc
		(start 360.145584 -227.64496)
		(mid 360.193263 -227.46206)
		(end 360.324146 -227.325682)
		(width 0.0889)
		(layer "In6.Cu")
		(net "DMI_CPU0_PCH_TX_DN<0>")
	)
	(arc
		(start 362.688378 -224.875344)
		(mid 362.890965 -224.668993)
		(end 362.964984 -224.389442)
		(width 0.0889)
		(layer "In6.Cu")
		(net "DMI_CPU0_PCH_TX_DN<0>")
	)
	(arc
		(start 363.152436 -224.065084)
		(mid 363.356771 -223.862479)
		(end 363.434884 -223.585532)
		(width 0.0889)
		(layer "In6.Cu")
		(net "DMI_CPU0_PCH_TX_DN<0>")
	)
	(arc
		(start 361.263946 -224.70872)
		(mid 361.08547 -224.389442)
		(end 361.263946 -224.070164)
		(width 0.0889)
		(layer "In6.Cu")
		(net "DMI_CPU0_PCH_TX_DN<0>")
	)
	(arc
		(start 365.507778 -221.619826)
		(mid 365.710365 -221.413475)
		(end 365.784384 -221.133924)
		(width 0.0889)
		(layer "In6.Cu")
		(net "DMI_CPU0_PCH_TX_DN<0>")
	)
	(arc
		(start 365.784384 -219.506038)
		(mid 365.832063 -219.323138)
		(end 365.962946 -219.18676)
		(width 0.0889)
		(layer "In6.Cu")
		(net "DMI_CPU0_PCH_TX_DN<0>")
	)
	(arc
		(start 361.272836 -224.065084)
		(mid 361.460034 -224.014941)
		(end 361.647232 -224.065084)
		(width 0.0889)
		(layer "In6.Cu")
		(net "DMI_CPU0_PCH_TX_DN<0>")
	)
	(arc
		(start 361.656122 -224.070164)
		(mid 361.787036 -224.206524)
		(end 361.834684 -224.389442)
		(width 0.0889)
		(layer "In6.Cu")
		(net "DMI_CPU0_PCH_TX_DN<0>")
	)
	(arc
		(start 360.333036 -227.320602)
		(mid 360.537371 -227.117997)
		(end 360.615484 -226.84105)
		(width 0.0889)
		(layer "In6.Cu")
		(net "DMI_CPU0_PCH_TX_DN<0>")
	)
	(arc
		(start 366.724184 -216.25052)
		(mid 366.771863 -216.06762)
		(end 366.902746 -215.931242)
		(width 0.0889)
		(layer "In6.Cu")
		(net "DMI_CPU0_PCH_TX_DN<0>")
	)
	(arc
		(start 365.971836 -219.18168)
		(mid 366.174659 -218.981449)
		(end 366.25403 -218.707716)
		(width 0.0889)
		(layer "In6.Cu")
		(net "DMI_CPU0_PCH_TX_DN<0>")
	)
	(arc
		(start 360.611928 -228.393752)
		(mid 360.610633 -228.383071)
		(end 360.609134 -228.372416)
		(width 0.0889)
		(layer "In6.Cu")
		(net "DMI_CPU0_PCH_TX_DN<0>")
	)
	(arc
		(start 365.493046 -220.639132)
		(mid 365.314449 -220.319854)
		(end 365.493046 -220.000576)
		(width 0.0889)
		(layer "In6.Cu")
		(net "DMI_CPU0_PCH_TX_DN<0>")
	)
	(arc
		(start 360.324146 -227.964238)
		(mid 360.196892 -227.834272)
		(end 360.145838 -227.659692)
		(width 0.0889)
		(layer "In6.Cu")
		(net "DMI_CPU0_PCH_TX_DN<0>")
	)
	(arc
		(start 364.561882 -223.251268)
		(mid 364.765363 -223.050464)
		(end 364.844584 -222.77578)
		(width 0.0889)
		(layer "In6.Cu")
		(net "DMI_CPU0_PCH_TX_DN<0>")
	)
	(arc
		(start 366.254284 -217.0557)
		(mid 366.306554 -216.873335)
		(end 366.441482 -216.739978)
		(width 0.0889)
		(layer "In6.Cu")
		(net "DMI_CPU0_PCH_TX_DN<0>")
	)
	(arc
		(start 362.116878 -224.8789)
		(mid 362.391077 -224.954735)
		(end 362.66755 -224.887536)
		(width 0.0889)
		(layer "In6.Cu")
		(net "DMI_CPU0_PCH_TX_DN<0>")
	)
	(arc
		(start 366.25403 -218.692222)
		(mid 366.301709 -218.509322)
		(end 366.432592 -218.372944)
		(width 0.0889)
		(layer "In6.Cu")
		(net "DMI_CPU0_PCH_TX_DN<0>")
	)
	(arc
		(start 366.447578 -216.736422)
		(mid 366.650165 -216.530071)
		(end 366.724184 -216.25052)
		(width 0.0889)
		(layer "In6.Cu")
		(net "DMI_CPU0_PCH_TX_DN<0>")
	)
	(arc
		(start 367.38052 -215.112092)
		(mid 367.442004 -215.071097)
		(end 367.497614 -215.02243)
		(width 0.0889)
		(layer "In6.Cu")
		(net "DMI_CPU0_PCH_TX_DN<0>")
	)
	(arc
		(start 367.19383 -215.436704)
		(mid 367.241509 -215.253804)
		(end 367.372392 -215.117426)
		(width 0.0889)
		(layer "In6.Cu")
		(net "DMI_CPU0_PCH_TX_DN<0>")
	)
	(arc
		(start 362.964984 -224.389442)
		(mid 363.012663 -224.206542)
		(end 363.143546 -224.070164)
		(width 0.0889)
		(layer "In6.Cu")
		(net "DMI_CPU0_PCH_TX_DN<0>")
	)
	(arc
		(start 361.085638 -226.002596)
		(mid 361.136692 -225.828016)
		(end 361.263946 -225.69805)
		(width 0.0889)
		(layer "In6.Cu")
		(net "DMI_CPU0_PCH_TX_DN<0>")
	)
	(arc
		(start 363.996732 -223.251268)
		(mid 364.273291 -223.326977)
		(end 364.551468 -223.257364)
		(width 0.0889)
		(layer "In6.Cu")
		(net "DMI_CPU0_PCH_TX_DN<0>")
	)
	(arc
		(start 360.808778 -226.50323)
		(mid 361.011365 -226.296879)
		(end 361.085384 -226.017328)
		(width 0.0889)
		(layer "In6.Cu")
		(net "DMI_CPU0_PCH_TX_DN<0>")
	)
	(arc
		(start 361.834684 -224.404936)
		(mid 361.914054 -224.67867)
		(end 362.116878 -224.8789)
		(width 0.0889)
		(layer "In6.Cu")
		(net "DMI_CPU0_PCH_TX_DN<0>")
	)
	(segment
		(start 347.786706 -61.025786)
		(end 347.820996 -61.060076)
		(width 0.0889)
		(layer "F.Cu")
		(net "DMI_CPU0_PCH_TX_C_DP<7>")
	)
	(segment
		(start 348.197424 -61.060076)
		(end 348.490032 -61.352684)
		(width 0.13208)
		(layer "F.Cu")
		(net "DMI_CPU0_PCH_TX_C_DP<7>")
	)
	(segment
		(start 345.267534 -60.728098)
		(end 345.392756 -60.779914)
		(width 0.0889)
		(layer "F.Cu")
		(net "DMI_CPU0_PCH_TX_C_DP<7>")
	)
	(segment
		(start 344.21318 -59.673744)
		(end 345.267534 -60.728098)
		(width 0.0889)
		(layer "F.Cu")
		(net "DMI_CPU0_PCH_TX_C_DP<7>")
	)
	(segment
		(start 344.092022 -58.772298)
		(end 344.092022 -58.904632)
		(width 0.0889)
		(layer "F.Cu")
		(net "DMI_CPU0_PCH_TX_C_DP<7>")
	)
	(segment
		(start 350.270826 -61.352684)
		(end 350.424496 -61.506354)
		(width 0.13208)
		(layer "F.Cu")
		(net "DMI_CPU0_PCH_TX_C_DP<7>")
	)
	(segment
		(start 348.490032 -61.352684)
		(end 350.270826 -61.352684)
		(width 0.13208)
		(layer "F.Cu")
		(net "DMI_CPU0_PCH_TX_C_DP<7>")
	)
	(segment
		(start 344.092022 -58.904632)
		(end 344.15095 -59.046872)
		(width 0.0889)
		(layer "F.Cu")
		(net "DMI_CPU0_PCH_TX_C_DP<7>")
	)
	(segment
		(start 345.9861 -61.025786)
		(end 347.786706 -61.025786)
		(width 0.0889)
		(layer "F.Cu")
		(net "DMI_CPU0_PCH_TX_C_DP<7>")
	)
	(segment
		(start 344.15095 -59.046872)
		(end 344.21318 -59.109102)
		(width 0.0889)
		(layer "F.Cu")
		(net "DMI_CPU0_PCH_TX_C_DP<7>")
	)
	(segment
		(start 347.843094 -61.060076)
		(end 348.197424 -61.060076)
		(width 0.13208)
		(layer "F.Cu")
		(net "DMI_CPU0_PCH_TX_C_DP<7>")
	)
	(segment
		(start 344.253058 -58.410094)
		(end 344.092022 -58.772298)
		(width 0.0889)
		(layer "F.Cu")
		(net "DMI_CPU0_PCH_TX_C_DP<7>")
	)
	(segment
		(start 344.21318 -59.109102)
		(end 344.21318 -59.673744)
		(width 0.0889)
		(layer "F.Cu")
		(net "DMI_CPU0_PCH_TX_C_DP<7>")
	)
	(segment
		(start 345.392756 -60.779914)
		(end 345.9861 -61.025786)
		(width 0.0889)
		(layer "F.Cu")
		(net "DMI_CPU0_PCH_TX_C_DP<7>")
	)
	(segment
		(start 347.820996 -61.060076)
		(end 347.843094 -61.060076)
		(width 0.0889)
		(layer "F.Cu")
		(net "DMI_CPU0_PCH_TX_C_DP<7>")
	)
	(segment
		(start 344.403426 -58.020204)
		(end 344.253058 -58.410094)
		(width 0.0889)
		(layer "F.Cu")
		(net "DMI_CPU0_PCH_TX_C_DP<7>")
	)
	(segment
		(start 348.483682 -63.165228)
		(end 347.871288 -62.813438)
		(width 0.13208)
		(layer "F.Cu")
		(net "DMI_CPU0_PCH_TX_C_DP<6>")
	)
	(segment
		(start 344.918792 -61.080396)
		(end 344.917268 -61.080396)
		(width 0.0889)
		(layer "F.Cu")
		(net "DMI_CPU0_PCH_TX_C_DP<6>")
	)
	(segment
		(start 346.455238 -62.000892)
		(end 346.442792 -61.95441)
		(width 0.0889)
		(layer "F.Cu")
		(net "DMI_CPU0_PCH_TX_C_DP<6>")
	)
	(segment
		(start 348.67088 -63.165228)
		(end 348.483682 -63.165228)
		(width 0.13208)
		(layer "F.Cu")
		(net "DMI_CPU0_PCH_TX_C_DP<6>")
	)
	(segment
		(start 346.474288 -62.011814)
		(end 346.455238 -62.000892)
		(width 0.0889)
		(layer "F.Cu")
		(net "DMI_CPU0_PCH_TX_C_DP<6>")
	)
	(segment
		(start 343.7128 -59.875928)
		(end 343.7128 -59.603386)
		(width 0.0889)
		(layer "F.Cu")
		(net "DMI_CPU0_PCH_TX_C_DP<6>")
	)
	(segment
		(start 343.7128 -59.603386)
		(end 343.626186 -59.516772)
		(width 0.0889)
		(layer "F.Cu")
		(net "DMI_CPU0_PCH_TX_C_DP<6>")
	)
	(segment
		(start 348.8182 -63.312548)
		(end 348.67088 -63.165228)
		(width 0.13208)
		(layer "F.Cu")
		(net "DMI_CPU0_PCH_TX_C_DP<6>")
	)
	(segment
		(start 343.626186 -59.516772)
		(end 343.626186 -59.219846)
		(width 0.0889)
		(layer "F.Cu")
		(net "DMI_CPU0_PCH_TX_C_DP<6>")
	)
	(segment
		(start 343.626186 -59.219846)
		(end 343.670636 -58.996326)
		(width 0.0889)
		(layer "F.Cu")
		(net "DMI_CPU0_PCH_TX_C_DP<6>")
	)
	(segment
		(start 347.871288 -62.813692)
		(end 346.474288 -62.011814)
		(width 0.13208)
		(layer "F.Cu")
		(net "DMI_CPU0_PCH_TX_C_DP<6>")
	)
	(segment
		(start 346.442792 -61.95441)
		(end 344.918792 -61.080396)
		(width 0.0889)
		(layer "F.Cu")
		(net "DMI_CPU0_PCH_TX_C_DP<6>")
	)
	(segment
		(start 347.871288 -62.813438)
		(end 347.871288 -62.813692)
		(width 0.13208)
		(layer "F.Cu")
		(net "DMI_CPU0_PCH_TX_C_DP<6>")
	)
	(segment
		(start 343.670636 -58.996326)
		(end 343.903046 -58.43524)
		(width 0.0889)
		(layer "F.Cu")
		(net "DMI_CPU0_PCH_TX_C_DP<6>")
	)
	(segment
		(start 344.407998 -60.571126)
		(end 344.407744 -60.571126)
		(width 0.0889)
		(layer "F.Cu")
		(net "DMI_CPU0_PCH_TX_C_DP<6>")
	)
	(segment
		(start 344.407744 -60.571126)
		(end 343.7128 -59.875928)
		(width 0.0889)
		(layer "F.Cu")
		(net "DMI_CPU0_PCH_TX_C_DP<6>")
	)
	(segment
		(start 344.917268 -61.080396)
		(end 344.407998 -60.571126)
		(width 0.0889)
		(layer "F.Cu")
		(net "DMI_CPU0_PCH_TX_C_DP<6>")
	)
	(segment
		(start 345.881198 -63.139828)
		(end 348.906846 -65.161668)
		(width 0.13208)
		(layer "F.Cu")
		(net "DMI_CPU0_PCH_TX_C_DP<5>")
	)
	(segment
		(start 343.212674 -59.2201)
		(end 343.212674 -60.314586)
		(width 0.0889)
		(layer "F.Cu")
		(net "DMI_CPU0_PCH_TX_C_DP<5>")
	)
	(segment
		(start 351.215706 -65.161668)
		(end 351.409 -65.354962)
		(width 0.13208)
		(layer "F.Cu")
		(net "DMI_CPU0_PCH_TX_C_DP<5>")
	)
	(segment
		(start 343.868756 -60.970668)
		(end 343.868756 -61.078618)
		(width 0.0889)
		(layer "F.Cu")
		(net "DMI_CPU0_PCH_TX_C_DP<5>")
	)
	(segment
		(start 343.868756 -61.078618)
		(end 345.766898 -62.97676)
		(width 0.0889)
		(layer "F.Cu")
		(net "DMI_CPU0_PCH_TX_C_DP<5>")
	)
	(segment
		(start 345.766898 -63.025528)
		(end 345.782392 -63.041022)
		(width 0.0889)
		(layer "F.Cu")
		(net "DMI_CPU0_PCH_TX_C_DP<5>")
	)
	(segment
		(start 348.906846 -65.161668)
		(end 351.215706 -65.161668)
		(width 0.13208)
		(layer "F.Cu")
		(net "DMI_CPU0_PCH_TX_C_DP<5>")
	)
	(segment
		(start 343.104216 -58.957972)
		(end 343.212674 -59.2201)
		(width 0.0889)
		(layer "F.Cu")
		(net "DMI_CPU0_PCH_TX_C_DP<5>")
	)
	(segment
		(start 343.104216 -58.741056)
		(end 343.104216 -58.957972)
		(width 0.0889)
		(layer "F.Cu")
		(net "DMI_CPU0_PCH_TX_C_DP<5>")
	)
	(segment
		(start 345.782392 -63.041022)
		(end 345.881198 -63.139828)
		(width 0.13208)
		(layer "F.Cu")
		(net "DMI_CPU0_PCH_TX_C_DP<5>")
	)
	(segment
		(start 345.766898 -62.97676)
		(end 345.766898 -63.025528)
		(width 0.0889)
		(layer "F.Cu")
		(net "DMI_CPU0_PCH_TX_C_DP<5>")
	)
	(segment
		(start 343.40292 -58.020204)
		(end 343.104216 -58.741056)
		(width 0.0889)
		(layer "F.Cu")
		(net "DMI_CPU0_PCH_TX_C_DP<5>")
	)
	(segment
		(start 343.212674 -60.314586)
		(end 343.868756 -60.970668)
		(width 0.0889)
		(layer "F.Cu")
		(net "DMI_CPU0_PCH_TX_C_DP<5>")
	)
	(segment
		(start 343.231724 -61.819536)
		(end 343.231724 -61.799978)
		(width 0.0889)
		(layer "F.Cu")
		(net "DMI_CPU0_PCH_TX_C_DP<4>")
	)
	(segment
		(start 342.712294 -60.594748)
		(end 342.712294 -59.634882)
		(width 0.0889)
		(layer "F.Cu")
		(net "DMI_CPU0_PCH_TX_C_DP<4>")
	)
	(segment
		(start 342.61044 -59.140344)
		(end 342.90254 -58.43524)
		(width 0.0889)
		(layer "F.Cu")
		(net "DMI_CPU0_PCH_TX_C_DP<4>")
	)
	(segment
		(start 342.61044 -59.533028)
		(end 342.61044 -59.140344)
		(width 0.0889)
		(layer "F.Cu")
		(net "DMI_CPU0_PCH_TX_C_DP<4>")
	)
	(segment
		(start 343.231724 -62.03442)
		(end 343.231724 -61.819536)
		(width 0.13208)
		(layer "F.Cu")
		(net "DMI_CPU0_PCH_TX_C_DP<4>")
	)
	(segment
		(start 343.267284 -61.149738)
		(end 342.712294 -60.594748)
		(width 0.0889)
		(layer "F.Cu")
		(net "DMI_CPU0_PCH_TX_C_DP<4>")
	)
	(segment
		(start 348.536768 -66.830448)
		(end 348.027752 -66.830448)
		(width 0.13208)
		(layer "F.Cu")
		(net "DMI_CPU0_PCH_TX_C_DP<4>")
	)
	(segment
		(start 343.231724 -61.799978)
		(end 343.267284 -61.764418)
		(width 0.0889)
		(layer "F.Cu")
		(net "DMI_CPU0_PCH_TX_C_DP<4>")
	)
	(segment
		(start 348.027752 -66.830448)
		(end 343.231724 -62.03442)
		(width 0.13208)
		(layer "F.Cu")
		(net "DMI_CPU0_PCH_TX_C_DP<4>")
	)
	(segment
		(start 342.712294 -59.634882)
		(end 342.61044 -59.533028)
		(width 0.0889)
		(layer "F.Cu")
		(net "DMI_CPU0_PCH_TX_C_DP<4>")
	)
	(segment
		(start 348.695264 -66.988944)
		(end 348.536768 -66.830448)
		(width 0.13208)
		(layer "F.Cu")
		(net "DMI_CPU0_PCH_TX_C_DP<4>")
	)
	(segment
		(start 343.267284 -61.764418)
		(end 343.267284 -61.149738)
		(width 0.0889)
		(layer "F.Cu")
		(net "DMI_CPU0_PCH_TX_C_DP<4>")
	)
	(segment
		(start 342.587326 -61.234828)
		(end 342.212168 -60.85967)
		(width 0.0889)
		(layer "F.Cu")
		(net "DMI_CPU0_PCH_TX_C_DP<3>")
	)
	(segment
		(start 348.288102 -68.974208)
		(end 344.968576 -65.654682)
		(width 0.13208)
		(layer "F.Cu")
		(net "DMI_CPU0_PCH_TX_C_DP<3>")
	)
	(segment
		(start 342.094312 -58.763916)
		(end 342.402414 -58.020204)
		(width 0.0889)
		(layer "F.Cu")
		(net "DMI_CPU0_PCH_TX_C_DP<3>")
	)
	(segment
		(start 344.968576 -65.423288)
		(end 342.552782 -63.007494)
		(width 0.13208)
		(layer "F.Cu")
		(net "DMI_CPU0_PCH_TX_C_DP<3>")
	)
	(segment
		(start 342.094312 -58.991246)
		(end 342.094312 -58.763916)
		(width 0.0889)
		(layer "F.Cu")
		(net "DMI_CPU0_PCH_TX_C_DP<3>")
	)
	(segment
		(start 342.552782 -62.674246)
		(end 342.552782 -62.652148)
		(width 0.0889)
		(layer "F.Cu")
		(net "DMI_CPU0_PCH_TX_C_DP<3>")
	)
	(segment
		(start 342.587326 -62.617604)
		(end 342.587326 -61.234828)
		(width 0.0889)
		(layer "F.Cu")
		(net "DMI_CPU0_PCH_TX_C_DP<3>")
	)
	(segment
		(start 342.212168 -60.85967)
		(end 342.212168 -59.109102)
		(width 0.0889)
		(layer "F.Cu")
		(net "DMI_CPU0_PCH_TX_C_DP<3>")
	)
	(segment
		(start 342.212168 -59.109102)
		(end 342.094312 -58.991246)
		(width 0.0889)
		(layer "F.Cu")
		(net "DMI_CPU0_PCH_TX_C_DP<3>")
	)
	(segment
		(start 344.968576 -65.654682)
		(end 344.968576 -65.423288)
		(width 0.13208)
		(layer "F.Cu")
		(net "DMI_CPU0_PCH_TX_C_DP<3>")
	)
	(segment
		(start 348.590362 -68.974208)
		(end 348.288102 -68.974208)
		(width 0.13208)
		(layer "F.Cu")
		(net "DMI_CPU0_PCH_TX_C_DP<3>")
	)
	(segment
		(start 342.552782 -62.652148)
		(end 342.587326 -62.617604)
		(width 0.0889)
		(layer "F.Cu")
		(net "DMI_CPU0_PCH_TX_C_DP<3>")
	)
	(segment
		(start 342.552782 -63.007494)
		(end 342.552782 -62.674246)
		(width 0.13208)
		(layer "F.Cu")
		(net "DMI_CPU0_PCH_TX_C_DP<3>")
	)
	(segment
		(start 348.747334 -69.13118)
		(end 348.590362 -68.974208)
		(width 0.13208)
		(layer "F.Cu")
		(net "DMI_CPU0_PCH_TX_C_DP<3>")
	)
	(segment
		(start 341.902034 -58.43524)
		(end 341.593932 -59.178952)
		(width 0.0889)
		(layer "F.Cu")
		(net "DMI_CPU0_PCH_TX_C_DP<2>")
	)
	(segment
		(start 344.060018 -65.634362)
		(end 344.060018 -66.211704)
		(width 0.0889)
		(layer "F.Cu")
		(net "DMI_CPU0_PCH_TX_C_DP<2>")
	)
	(segment
		(start 344.945716 -68.174108)
		(end 345.77274 -68.174108)
		(width 0.13208)
		(layer "F.Cu")
		(net "DMI_CPU0_PCH_TX_C_DP<2>")
	)
	(segment
		(start 341.931244 -63.505588)
		(end 344.060018 -65.634362)
		(width 0.0889)
		(layer "F.Cu")
		(net "DMI_CPU0_PCH_TX_C_DP<2>")
	)
	(segment
		(start 341.594186 -59.382914)
		(end 341.594186 -60.79236)
		(width 0.0889)
		(layer "F.Cu")
		(net "DMI_CPU0_PCH_TX_C_DP<2>")
	)
	(segment
		(start 344.025474 -66.246248)
		(end 344.025474 -66.268346)
		(width 0.0889)
		(layer "F.Cu")
		(net "DMI_CPU0_PCH_TX_C_DP<2>")
	)
	(segment
		(start 344.060018 -66.211704)
		(end 344.025474 -66.246248)
		(width 0.0889)
		(layer "F.Cu")
		(net "DMI_CPU0_PCH_TX_C_DP<2>")
	)
	(segment
		(start 346.116656 -68.778374)
		(end 345.79179 -69.10324)
		(width 0.13208)
		(layer "F.Cu")
		(net "DMI_CPU0_PCH_TX_C_DP<2>")
	)
	(segment
		(start 341.593932 -59.38266)
		(end 341.594186 -59.382914)
		(width 0.0889)
		(layer "F.Cu")
		(net "DMI_CPU0_PCH_TX_C_DP<2>")
	)
	(segment
		(start 345.77274 -68.174108)
		(end 346.116656 -68.518024)
		(width 0.13208)
		(layer "F.Cu")
		(net "DMI_CPU0_PCH_TX_C_DP<2>")
	)
	(segment
		(start 341.931244 -61.129418)
		(end 341.931244 -63.505588)
		(width 0.0889)
		(layer "F.Cu")
		(net "DMI_CPU0_PCH_TX_C_DP<2>")
	)
	(segment
		(start 341.594186 -60.79236)
		(end 341.931244 -61.129418)
		(width 0.0889)
		(layer "F.Cu")
		(net "DMI_CPU0_PCH_TX_C_DP<2>")
	)
	(segment
		(start 344.025474 -66.268346)
		(end 344.025474 -67.253866)
		(width 0.13208)
		(layer "F.Cu")
		(net "DMI_CPU0_PCH_TX_C_DP<2>")
	)
	(segment
		(start 344.025474 -67.253866)
		(end 344.945716 -68.174108)
		(width 0.13208)
		(layer "F.Cu")
		(net "DMI_CPU0_PCH_TX_C_DP<2>")
	)
	(segment
		(start 341.593932 -59.178952)
		(end 341.593932 -59.38266)
		(width 0.0889)
		(layer "F.Cu")
		(net "DMI_CPU0_PCH_TX_C_DP<2>")
	)
	(segment
		(start 346.116656 -68.518024)
		(end 346.116656 -68.778374)
		(width 0.13208)
		(layer "F.Cu")
		(net "DMI_CPU0_PCH_TX_C_DP<2>")
	)
	(segment
		(start 341.119714 -58.6994)
		(end 341.401908 -58.020204)
		(width 0.0889)
		(layer "F.Cu")
		(net "DMI_CPU0_PCH_TX_C_DP<1>")
	)
	(segment
		(start 341.408512 -64.235838)
		(end 341.408512 -61.264292)
		(width 0.0889)
		(layer "F.Cu")
		(net "DMI_CPU0_PCH_TX_C_DP<1>")
	)
	(segment
		(start 342.499188 -65.326514)
		(end 341.408512 -64.235838)
		(width 0.0889)
		(layer "F.Cu")
		(net "DMI_CPU0_PCH_TX_C_DP<1>")
	)
	(segment
		(start 343.73439 -70.25386)
		(end 344.053414 -69.934836)
		(width 0.13208)
		(layer "F.Cu")
		(net "DMI_CPU0_PCH_TX_C_DP<1>")
	)
	(segment
		(start 342.464644 -68.007992)
		(end 342.464644 -65.607946)
		(width 0.13208)
		(layer "F.Cu")
		(net "DMI_CPU0_PCH_TX_C_DP<1>")
	)
	(segment
		(start 342.499188 -65.551304)
		(end 342.499188 -65.326514)
		(width 0.0889)
		(layer "F.Cu")
		(net "DMI_CPU0_PCH_TX_C_DP<1>")
	)
	(segment
		(start 344.053414 -69.806312)
		(end 342.612726 -68.365624)
		(width 0.13208)
		(layer "F.Cu")
		(net "DMI_CPU0_PCH_TX_C_DP<1>")
	)
	(segment
		(start 342.464644 -65.585848)
		(end 342.499188 -65.551304)
		(width 0.0889)
		(layer "F.Cu")
		(net "DMI_CPU0_PCH_TX_C_DP<1>")
	)
	(segment
		(start 342.464644 -65.607946)
		(end 342.464644 -65.585848)
		(width 0.0889)
		(layer "F.Cu")
		(net "DMI_CPU0_PCH_TX_C_DP<1>")
	)
	(segment
		(start 344.053414 -69.934836)
		(end 344.053414 -69.806312)
		(width 0.13208)
		(layer "F.Cu")
		(net "DMI_CPU0_PCH_TX_C_DP<1>")
	)
	(segment
		(start 341.099394 -58.786014)
		(end 341.119714 -58.6994)
		(width 0.0889)
		(layer "F.Cu")
		(net "DMI_CPU0_PCH_TX_C_DP<1>")
	)
	(segment
		(start 341.408512 -61.264292)
		(end 341.211662 -61.067442)
		(width 0.0889)
		(layer "F.Cu")
		(net "DMI_CPU0_PCH_TX_C_DP<1>")
	)
	(segment
		(start 341.11057 -58.95467)
		(end 341.093298 -58.87466)
		(width 0.0889)
		(layer "F.Cu")
		(net "DMI_CPU0_PCH_TX_C_DP<1>")
	)
	(segment
		(start 342.612726 -68.365624)
		(end 342.464644 -68.007992)
		(width 0.13208)
		(layer "F.Cu")
		(net "DMI_CPU0_PCH_TX_C_DP<1>")
	)
	(segment
		(start 341.211662 -59.141614)
		(end 341.11057 -58.95467)
		(width 0.0889)
		(layer "F.Cu")
		(net "DMI_CPU0_PCH_TX_C_DP<1>")
	)
	(segment
		(start 341.211662 -61.067442)
		(end 341.211662 -59.141614)
		(width 0.0889)
		(layer "F.Cu")
		(net "DMI_CPU0_PCH_TX_C_DP<1>")
	)
	(segment
		(start 341.093298 -58.87466)
		(end 341.099394 -58.786014)
		(width 0.0889)
		(layer "F.Cu")
		(net "DMI_CPU0_PCH_TX_C_DP<1>")
	)
	(segment
		(start 341.854536 -69.225922)
		(end 341.854536 -69.441314)
		(width 0.13208)
		(layer "F.Cu")
		(net "DMI_CPU0_PCH_TX_C_DP<0>")
	)
	(segment
		(start 341.310976 -65.750948)
		(end 341.310976 -67.912996)
		(width 0.13208)
		(layer "F.Cu")
		(net "DMI_CPU0_PCH_TX_C_DP<0>")
	)
	(segment
		(start 340.59368 -61.160152)
		(end 340.822534 -61.389006)
		(width 0.0889)
		(layer "F.Cu")
		(net "DMI_CPU0_PCH_TX_C_DP<0>")
	)
	(segment
		(start 340.59368 -59.178952)
		(end 340.59368 -61.160152)
		(width 0.0889)
		(layer "F.Cu")
		(net "DMI_CPU0_PCH_TX_C_DP<0>")
	)
	(segment
		(start 341.310976 -67.912996)
		(end 341.854536 -69.225922)
		(width 0.13208)
		(layer "F.Cu")
		(net "DMI_CPU0_PCH_TX_C_DP<0>")
	)
	(segment
		(start 340.901782 -58.43524)
		(end 340.59368 -59.178952)
		(width 0.0889)
		(layer "F.Cu")
		(net "DMI_CPU0_PCH_TX_C_DP<0>")
	)
	(segment
		(start 341.34679 -65.333118)
		(end 341.34679 -65.703958)
		(width 0.0889)
		(layer "F.Cu")
		(net "DMI_CPU0_PCH_TX_C_DP<0>")
	)
	(segment
		(start 341.34679 -65.703958)
		(end 341.310976 -65.739772)
		(width 0.0889)
		(layer "F.Cu")
		(net "DMI_CPU0_PCH_TX_C_DP<0>")
	)
	(segment
		(start 341.310976 -65.739772)
		(end 341.310976 -65.750948)
		(width 0.0889)
		(layer "F.Cu")
		(net "DMI_CPU0_PCH_TX_C_DP<0>")
	)
	(segment
		(start 340.822534 -64.808862)
		(end 341.34679 -65.333118)
		(width 0.0889)
		(layer "F.Cu")
		(net "DMI_CPU0_PCH_TX_C_DP<0>")
	)
	(segment
		(start 341.854536 -69.441314)
		(end 341.52459 -69.77126)
		(width 0.13208)
		(layer "F.Cu")
		(net "DMI_CPU0_PCH_TX_C_DP<0>")
	)
	(segment
		(start 340.822534 -61.389006)
		(end 340.822534 -64.808862)
		(width 0.0889)
		(layer "F.Cu")
		(net "DMI_CPU0_PCH_TX_C_DP<0>")
	)
	(segment
		(start 344.75928 -59.95035)
		(end 344.75928 -59.810142)
		(width 0.0889)
		(layer "F.Cu")
		(net "DMI_CPU0_PCH_TX_C_DN<7>")
	)
	(segment
		(start 345.115134 -60.306204)
		(end 345.115134 -60.165742)
		(width 0.0889)
		(layer "F.Cu")
		(net "DMI_CPU0_PCH_TX_C_DN<7>")
	)
	(segment
		(start 347.18244 -60.83554)
		(end 347.03004 -60.83554)
		(width 0.0889)
		(layer "F.Cu")
		(net "DMI_CPU0_PCH_TX_C_DN<7>")
	)
	(segment
		(start 344.502486 -59.24169)
		(end 344.403426 -59.14263)
		(width 0.0889)
		(layer "F.Cu")
		(net "DMI_CPU0_PCH_TX_C_DN<7>")
	)
	(segment
		(start 346.023946 -60.835286)
		(end 345.847416 -60.762134)
		(width 0.0889)
		(layer "F.Cu")
		(net "DMI_CPU0_PCH_TX_C_DN<7>")
	)
	(segment
		(start 346.27566 -60.73648)
		(end 346.1766 -60.83554)
		(width 0.0889)
		(layer "F.Cu")
		(net "DMI_CPU0_PCH_TX_C_DN<7>")
	)
	(segment
		(start 347.2815 -60.73648)
		(end 347.18244 -60.83554)
		(width 0.0889)
		(layer "F.Cu")
		(net "DMI_CPU0_PCH_TX_C_DN<7>")
	)
	(segment
		(start 346.77858 -60.73648)
		(end 346.67952 -60.83554)
		(width 0.0889)
		(layer "F.Cu")
		(net "DMI_CPU0_PCH_TX_C_DN<7>")
	)
	(segment
		(start 347.4339 -60.73648)
		(end 347.2815 -60.73648)
		(width 0.0889)
		(layer "F.Cu")
		(net "DMI_CPU0_PCH_TX_C_DN<7>")
	)
	(segment
		(start 349.685102 -60.970414)
		(end 349.561912 -61.093604)
		(width 0.13208)
		(layer "F.Cu")
		(net "DMI_CPU0_PCH_TX_C_DN<7>")
	)
	(segment
		(start 350.424496 -60.953904)
		(end 350.284796 -61.093604)
		(width 0.13208)
		(layer "F.Cu")
		(net "DMI_CPU0_PCH_TX_C_DN<7>")
	)
	(segment
		(start 345.375484 -60.566554)
		(end 345.115134 -60.306204)
		(width 0.0889)
		(layer "F.Cu")
		(net "DMI_CPU0_PCH_TX_C_DN<7>")
	)
	(segment
		(start 344.866976 -60.058046)
		(end 344.75928 -59.95035)
		(width 0.0889)
		(layer "F.Cu")
		(net "DMI_CPU0_PCH_TX_C_DN<7>")
	)
	(segment
		(start 346.0242 -60.83554)
		(end 346.023946 -60.835286)
		(width 0.0889)
		(layer "F.Cu")
		(net "DMI_CPU0_PCH_TX_C_DN<7>")
	)
	(segment
		(start 345.793822 -60.632594)
		(end 345.652852 -60.574174)
		(width 0.0889)
		(layer "F.Cu")
		(net "DMI_CPU0_PCH_TX_C_DN<7>")
	)
	(segment
		(start 345.652852 -60.574174)
		(end 345.523312 -60.627768)
		(width 0.0889)
		(layer "F.Cu")
		(net "DMI_CPU0_PCH_TX_C_DN<7>")
	)
	(segment
		(start 344.65133 -59.702446)
		(end 344.511122 -59.702446)
		(width 0.0889)
		(layer "F.Cu")
		(net "DMI_CPU0_PCH_TX_C_DN<7>")
	)
	(segment
		(start 347.843094 -60.800996)
		(end 347.820996 -60.800996)
		(width 0.0889)
		(layer "F.Cu")
		(net "DMI_CPU0_PCH_TX_C_DN<7>")
	)
	(segment
		(start 348.597474 -61.093604)
		(end 348.304866 -60.800996)
		(width 0.13208)
		(layer "F.Cu")
		(net "DMI_CPU0_PCH_TX_C_DN<7>")
	)
	(segment
		(start 348.716854 -61.093604)
		(end 348.597474 -61.093604)
		(width 0.13208)
		(layer "F.Cu")
		(net "DMI_CPU0_PCH_TX_C_DN<7>")
	)
	(segment
		(start 346.67952 -60.83554)
		(end 346.52712 -60.83554)
		(width 0.0889)
		(layer "F.Cu")
		(net "DMI_CPU0_PCH_TX_C_DN<7>")
	)
	(segment
		(start 346.93098 -60.73648)
		(end 346.77858 -60.73648)
		(width 0.0889)
		(layer "F.Cu")
		(net "DMI_CPU0_PCH_TX_C_DN<7>")
	)
	(segment
		(start 350.284796 -61.093604)
		(end 350.087692 -61.093604)
		(width 0.13208)
		(layer "F.Cu")
		(net "DMI_CPU0_PCH_TX_C_DN<7>")
	)
	(segment
		(start 349.964502 -60.970414)
		(end 349.685102 -60.970414)
		(width 0.13208)
		(layer "F.Cu")
		(net "DMI_CPU0_PCH_TX_C_DN<7>")
	)
	(segment
		(start 344.511122 -59.702446)
		(end 344.403426 -59.59475)
		(width 0.0889)
		(layer "F.Cu")
		(net "DMI_CPU0_PCH_TX_C_DN<7>")
	)
	(segment
		(start 347.786452 -60.83554)
		(end 347.53296 -60.83554)
		(width 0.0889)
		(layer "F.Cu")
		(net "DMI_CPU0_PCH_TX_C_DN<7>")
	)
	(segment
		(start 348.840044 -60.970414)
		(end 348.716854 -61.093604)
		(width 0.13208)
		(layer "F.Cu")
		(net "DMI_CPU0_PCH_TX_C_DN<7>")
	)
	(segment
		(start 344.403426 -59.46775)
		(end 344.502486 -59.36869)
		(width 0.0889)
		(layer "F.Cu")
		(net "DMI_CPU0_PCH_TX_C_DN<7>")
	)
	(segment
		(start 347.03004 -60.83554)
		(end 346.93098 -60.73648)
		(width 0.0889)
		(layer "F.Cu")
		(net "DMI_CPU0_PCH_TX_C_DN<7>")
	)
	(segment
		(start 349.561912 -61.093604)
		(end 349.242634 -61.093604)
		(width 0.13208)
		(layer "F.Cu")
		(net "DMI_CPU0_PCH_TX_C_DN<7>")
	)
	(segment
		(start 346.42806 -60.73648)
		(end 346.27566 -60.73648)
		(width 0.0889)
		(layer "F.Cu")
		(net "DMI_CPU0_PCH_TX_C_DN<7>")
	)
	(segment
		(start 346.1766 -60.83554)
		(end 346.0242 -60.83554)
		(width 0.0889)
		(layer "F.Cu")
		(net "DMI_CPU0_PCH_TX_C_DN<7>")
	)
	(segment
		(start 344.403426 -59.59475)
		(end 344.403426 -59.46775)
		(width 0.0889)
		(layer "F.Cu")
		(net "DMI_CPU0_PCH_TX_C_DN<7>")
	)
	(segment
		(start 347.53296 -60.83554)
		(end 347.4339 -60.73648)
		(width 0.0889)
		(layer "F.Cu")
		(net "DMI_CPU0_PCH_TX_C_DN<7>")
	)
	(segment
		(start 344.75928 -59.810142)
		(end 344.65133 -59.702446)
		(width 0.0889)
		(layer "F.Cu")
		(net "DMI_CPU0_PCH_TX_C_DN<7>")
	)
	(segment
		(start 348.304866 -60.800996)
		(end 347.843094 -60.800996)
		(width 0.13208)
		(layer "F.Cu")
		(net "DMI_CPU0_PCH_TX_C_DN<7>")
	)
	(segment
		(start 344.403426 -59.14263)
		(end 344.403426 -58.850276)
		(width 0.0889)
		(layer "F.Cu")
		(net "DMI_CPU0_PCH_TX_C_DN<7>")
	)
	(segment
		(start 350.424496 -60.591954)
		(end 350.424496 -60.953904)
		(width 0.13208)
		(layer "F.Cu")
		(net "DMI_CPU0_PCH_TX_C_DN<7>")
	)
	(segment
		(start 345.847416 -60.762134)
		(end 345.793822 -60.632594)
		(width 0.0889)
		(layer "F.Cu")
		(net "DMI_CPU0_PCH_TX_C_DN<7>")
	)
	(segment
		(start 345.392756 -60.573666)
		(end 345.375484 -60.566554)
		(width 0.0889)
		(layer "F.Cu")
		(net "DMI_CPU0_PCH_TX_C_DN<7>")
	)
	(segment
		(start 350.087692 -61.093604)
		(end 349.964502 -60.970414)
		(width 0.13208)
		(layer "F.Cu")
		(net "DMI_CPU0_PCH_TX_C_DN<7>")
	)
	(segment
		(start 349.242634 -61.093604)
		(end 349.119444 -60.970414)
		(width 0.13208)
		(layer "F.Cu")
		(net "DMI_CPU0_PCH_TX_C_DN<7>")
	)
	(segment
		(start 345.115134 -60.165742)
		(end 345.007184 -60.058046)
		(width 0.0889)
		(layer "F.Cu")
		(net "DMI_CPU0_PCH_TX_C_DN<7>")
	)
	(segment
		(start 347.820996 -60.800996)
		(end 347.786452 -60.83554)
		(width 0.0889)
		(layer "F.Cu")
		(net "DMI_CPU0_PCH_TX_C_DN<7>")
	)
	(segment
		(start 345.007184 -60.058046)
		(end 344.866976 -60.058046)
		(width 0.0889)
		(layer "F.Cu")
		(net "DMI_CPU0_PCH_TX_C_DN<7>")
	)
	(segment
		(start 345.523312 -60.627768)
		(end 345.392756 -60.573666)
		(width 0.0889)
		(layer "F.Cu")
		(net "DMI_CPU0_PCH_TX_C_DN<7>")
	)
	(segment
		(start 346.52712 -60.83554)
		(end 346.42806 -60.73648)
		(width 0.0889)
		(layer "F.Cu")
		(net "DMI_CPU0_PCH_TX_C_DN<7>")
	)
	(segment
		(start 349.119444 -60.970414)
		(end 348.840044 -60.970414)
		(width 0.13208)
		(layer "F.Cu")
		(net "DMI_CPU0_PCH_TX_C_DN<7>")
	)
	(segment
		(start 344.502486 -59.36869)
		(end 344.502486 -59.24169)
		(width 0.0889)
		(layer "F.Cu")
		(net "DMI_CPU0_PCH_TX_C_DN<7>")
	)
	(segment
		(start 346.60332 -61.787024)
		(end 346.845636 -61.925962)
		(width 0.13208)
		(layer "F.Cu")
		(net "DMI_CPU0_PCH_TX_C_DN<6>")
	)
	(segment
		(start 345.423998 -61.1505)
		(end 345.53398 -61.213492)
		(width 0.0889)
		(layer "F.Cu")
		(net "DMI_CPU0_PCH_TX_C_DN<6>")
	)
	(segment
		(start 347.544136 -62.326774)
		(end 347.712284 -62.281308)
		(width 0.13208)
		(layer "F.Cu")
		(net "DMI_CPU0_PCH_TX_C_DN<6>")
	)
	(segment
		(start 345.031568 -60.925456)
		(end 345.14155 -60.988448)
		(width 0.0889)
		(layer "F.Cu")
		(net "DMI_CPU0_PCH_TX_C_DN<6>")
	)
	(segment
		(start 346.845636 -61.925962)
		(end 347.013784 -61.880496)
		(width 0.13208)
		(layer "F.Cu")
		(net "DMI_CPU0_PCH_TX_C_DN<6>")
	)
	(segment
		(start 344.862404 -60.616084)
		(end 344.862404 -60.756292)
		(width 0.0889)
		(layer "F.Cu")
		(net "DMI_CPU0_PCH_TX_C_DN<6>")
	)
	(segment
		(start 345.387168 -61.015118)
		(end 345.423998 -61.1505)
		(width 0.0889)
		(layer "F.Cu")
		(net "DMI_CPU0_PCH_TX_C_DN<6>")
	)
	(segment
		(start 344.312494 -60.206382)
		(end 344.452956 -60.206382)
		(width 0.0889)
		(layer "F.Cu")
		(net "DMI_CPU0_PCH_TX_C_DN<6>")
	)
	(segment
		(start 346.208858 -61.600588)
		(end 346.53728 -61.789056)
		(width 0.0889)
		(layer "F.Cu")
		(net "DMI_CPU0_PCH_TX_C_DN<6>")
	)
	(segment
		(start 347.712284 -62.281308)
		(end 347.954854 -62.420246)
		(width 0.13208)
		(layer "F.Cu")
		(net "DMI_CPU0_PCH_TX_C_DN<6>")
	)
	(segment
		(start 343.992708 -59.886596)
		(end 344.13317 -59.886596)
		(width 0.0889)
		(layer "F.Cu")
		(net "DMI_CPU0_PCH_TX_C_DN<6>")
	)
	(segment
		(start 346.061792 -61.40196)
		(end 346.172028 -61.465206)
		(width 0.0889)
		(layer "F.Cu")
		(net "DMI_CPU0_PCH_TX_C_DN<6>")
	)
	(segment
		(start 347.013784 -61.880496)
		(end 347.256354 -62.019434)
		(width 0.13208)
		(layer "F.Cu")
		(net "DMI_CPU0_PCH_TX_C_DN<6>")
	)
	(segment
		(start 347.256354 -62.019434)
		(end 347.30182 -62.187836)
		(width 0.13208)
		(layer "F.Cu")
		(net "DMI_CPU0_PCH_TX_C_DN<6>")
	)
	(segment
		(start 344.002106 -59.582558)
		(end 343.903046 -59.681618)
		(width 0.0889)
		(layer "F.Cu")
		(net "DMI_CPU0_PCH_TX_C_DN<6>")
	)
	(segment
		(start 344.63228 -60.526168)
		(end 344.772742 -60.526168)
		(width 0.0889)
		(layer "F.Cu")
		(net "DMI_CPU0_PCH_TX_C_DN<6>")
	)
	(segment
		(start 343.903046 -59.681618)
		(end 343.903046 -59.796934)
		(width 0.0889)
		(layer "F.Cu")
		(net "DMI_CPU0_PCH_TX_C_DN<6>")
	)
	(segment
		(start 345.53398 -61.213492)
		(end 345.669362 -61.176916)
		(width 0.0889)
		(layer "F.Cu")
		(net "DMI_CPU0_PCH_TX_C_DN<6>")
	)
	(segment
		(start 345.779598 -61.240162)
		(end 345.816428 -61.375544)
		(width 0.0889)
		(layer "F.Cu")
		(net "DMI_CPU0_PCH_TX_C_DN<6>")
	)
	(segment
		(start 343.903046 -59.381898)
		(end 344.002106 -59.480958)
		(width 0.0889)
		(layer "F.Cu")
		(net "DMI_CPU0_PCH_TX_C_DN<6>")
	)
	(segment
		(start 345.14155 -60.988448)
		(end 345.276932 -60.951872)
		(width 0.0889)
		(layer "F.Cu")
		(net "DMI_CPU0_PCH_TX_C_DN<6>")
	)
	(segment
		(start 344.542618 -60.296298)
		(end 344.542618 -60.436506)
		(width 0.0889)
		(layer "F.Cu")
		(net "DMI_CPU0_PCH_TX_C_DN<6>")
	)
	(segment
		(start 346.53728 -61.789056)
		(end 346.58427 -61.776102)
		(width 0.0889)
		(layer "F.Cu")
		(net "DMI_CPU0_PCH_TX_C_DN<6>")
	)
	(segment
		(start 344.002106 -59.480958)
		(end 344.002106 -59.582558)
		(width 0.0889)
		(layer "F.Cu")
		(net "DMI_CPU0_PCH_TX_C_DN<6>")
	)
	(segment
		(start 348.7166 -62.906148)
		(end 348.8182 -62.804548)
		(width 0.13208)
		(layer "F.Cu")
		(net "DMI_CPU0_PCH_TX_C_DN<6>")
	)
	(segment
		(start 345.276932 -60.951872)
		(end 345.387168 -61.015118)
		(width 0.0889)
		(layer "F.Cu")
		(net "DMI_CPU0_PCH_TX_C_DN<6>")
	)
	(segment
		(start 344.542618 -60.436506)
		(end 344.63228 -60.526168)
		(width 0.0889)
		(layer "F.Cu")
		(net "DMI_CPU0_PCH_TX_C_DN<6>")
	)
	(segment
		(start 345.816428 -61.375544)
		(end 345.92641 -61.438536)
		(width 0.0889)
		(layer "F.Cu")
		(net "DMI_CPU0_PCH_TX_C_DN<6>")
	)
	(segment
		(start 343.903046 -59.796934)
		(end 343.992708 -59.886596)
		(width 0.0889)
		(layer "F.Cu")
		(net "DMI_CPU0_PCH_TX_C_DN<6>")
	)
	(segment
		(start 346.58427 -61.776102)
		(end 346.60332 -61.787024)
		(width 0.0889)
		(layer "F.Cu")
		(net "DMI_CPU0_PCH_TX_C_DN<6>")
	)
	(segment
		(start 348.8182 -62.804548)
		(end 348.8182 -62.398148)
		(width 0.13208)
		(layer "F.Cu")
		(net "DMI_CPU0_PCH_TX_C_DN<6>")
	)
	(segment
		(start 344.222832 -59.976512)
		(end 344.222832 -60.11672)
		(width 0.0889)
		(layer "F.Cu")
		(net "DMI_CPU0_PCH_TX_C_DN<6>")
	)
	(segment
		(start 344.13317 -59.886596)
		(end 344.222832 -59.976512)
		(width 0.0889)
		(layer "F.Cu")
		(net "DMI_CPU0_PCH_TX_C_DN<6>")
	)
	(segment
		(start 344.452956 -60.206382)
		(end 344.542618 -60.296298)
		(width 0.0889)
		(layer "F.Cu")
		(net "DMI_CPU0_PCH_TX_C_DN<6>")
	)
	(segment
		(start 344.862404 -60.756292)
		(end 345.031568 -60.925456)
		(width 0.0889)
		(layer "F.Cu")
		(net "DMI_CPU0_PCH_TX_C_DN<6>")
	)
	(segment
		(start 343.903046 -59.265312)
		(end 343.903046 -59.381898)
		(width 0.0889)
		(layer "F.Cu")
		(net "DMI_CPU0_PCH_TX_C_DN<6>")
	)
	(segment
		(start 347.30182 -62.187836)
		(end 347.544136 -62.326774)
		(width 0.13208)
		(layer "F.Cu")
		(net "DMI_CPU0_PCH_TX_C_DN<6>")
	)
	(segment
		(start 348.00032 -62.588648)
		(end 348.553024 -62.906148)
		(width 0.13208)
		(layer "F.Cu")
		(net "DMI_CPU0_PCH_TX_C_DN<6>")
	)
	(segment
		(start 344.772742 -60.526168)
		(end 344.862404 -60.616084)
		(width 0.0889)
		(layer "F.Cu")
		(net "DMI_CPU0_PCH_TX_C_DN<6>")
	)
	(segment
		(start 346.172028 -61.465206)
		(end 346.208858 -61.600588)
		(width 0.0889)
		(layer "F.Cu")
		(net "DMI_CPU0_PCH_TX_C_DN<6>")
	)
	(segment
		(start 345.669362 -61.176916)
		(end 345.779598 -61.240162)
		(width 0.0889)
		(layer "F.Cu")
		(net "DMI_CPU0_PCH_TX_C_DN<6>")
	)
	(segment
		(start 345.92641 -61.438536)
		(end 346.061792 -61.40196)
		(width 0.0889)
		(layer "F.Cu")
		(net "DMI_CPU0_PCH_TX_C_DN<6>")
	)
	(segment
		(start 347.954854 -62.420246)
		(end 348.00032 -62.588648)
		(width 0.13208)
		(layer "F.Cu")
		(net "DMI_CPU0_PCH_TX_C_DN<6>")
	)
	(segment
		(start 348.553024 -62.906148)
		(end 348.7166 -62.906148)
		(width 0.13208)
		(layer "F.Cu")
		(net "DMI_CPU0_PCH_TX_C_DN<6>")
	)
	(segment
		(start 344.222832 -60.11672)
		(end 344.312494 -60.206382)
		(width 0.0889)
		(layer "F.Cu")
		(net "DMI_CPU0_PCH_TX_C_DN<6>")
	)
	(segment
		(start 345.61145 -62.415166)
		(end 345.61145 -62.552072)
		(width 0.0889)
		(layer "F.Cu")
		(net "DMI_CPU0_PCH_TX_C_DN<5>")
	)
	(segment
		(start 344.835226 -61.775848)
		(end 344.960702 -61.901324)
		(width 0.0889)
		(layer "F.Cu")
		(net "DMI_CPU0_PCH_TX_C_DN<5>")
	)
	(segment
		(start 345.950286 -62.84214)
		(end 345.96578 -62.857634)
		(width 0.0889)
		(layer "F.Cu")
		(net "DMI_CPU0_PCH_TX_C_DN<5>")
	)
	(segment
		(start 344.184478 -61.1251)
		(end 344.321384 -61.1251)
		(width 0.0889)
		(layer "F.Cu")
		(net "DMI_CPU0_PCH_TX_C_DN<5>")
	)
	(segment
		(start 348.099634 -64.31026)
		(end 348.270322 -64.276478)
		(width 0.13208)
		(layer "F.Cu")
		(net "DMI_CPU0_PCH_TX_C_DN<5>")
	)
	(segment
		(start 348.270322 -64.276478)
		(end 348.600014 -64.496696)
		(width 0.13208)
		(layer "F.Cu")
		(net "DMI_CPU0_PCH_TX_C_DN<5>")
	)
	(segment
		(start 346.046552 -62.938406)
		(end 346.37599 -63.15837)
		(width 0.13208)
		(layer "F.Cu")
		(net "DMI_CPU0_PCH_TX_C_DN<5>")
	)
	(segment
		(start 343.903046 -60.735718)
		(end 344.059002 -60.891674)
		(width 0.0889)
		(layer "F.Cu")
		(net "DMI_CPU0_PCH_TX_C_DN<5>")
	)
	(segment
		(start 345.097608 -61.901324)
		(end 345.223338 -62.027054)
		(width 0.0889)
		(layer "F.Cu")
		(net "DMI_CPU0_PCH_TX_C_DN<5>")
	)
	(segment
		(start 347.406722 -63.70066)
		(end 347.736414 -63.921132)
		(width 0.13208)
		(layer "F.Cu")
		(net "DMI_CPU0_PCH_TX_C_DN<5>")
	)
	(segment
		(start 350.013016 -64.902588)
		(end 351.27692 -64.902588)
		(width 0.13208)
		(layer "F.Cu")
		(net "DMI_CPU0_PCH_TX_C_DN<5>")
	)
	(segment
		(start 348.600014 -64.496696)
		(end 348.63405 -64.667638)
		(width 0.13208)
		(layer "F.Cu")
		(net "DMI_CPU0_PCH_TX_C_DN<5>")
	)
	(segment
		(start 348.985586 -64.902588)
		(end 349.372936 -64.902588)
		(width 0.13208)
		(layer "F.Cu")
		(net "DMI_CPU0_PCH_TX_C_DN<5>")
	)
	(segment
		(start 343.903046 -60.598812)
		(end 343.903046 -60.735718)
		(width 0.0889)
		(layer "F.Cu")
		(net "DMI_CPU0_PCH_TX_C_DN<5>")
	)
	(segment
		(start 343.49944 -59.783472)
		(end 343.49944 -59.961272)
		(width 0.0889)
		(layer "F.Cu")
		(net "DMI_CPU0_PCH_TX_C_DN<5>")
	)
	(segment
		(start 345.223338 -62.16396)
		(end 345.348814 -62.289436)
		(width 0.0889)
		(layer "F.Cu")
		(net "DMI_CPU0_PCH_TX_C_DN<5>")
	)
	(segment
		(start 343.40292 -60.057792)
		(end 343.40292 -60.235592)
		(width 0.0889)
		(layer "F.Cu")
		(net "DMI_CPU0_PCH_TX_C_DN<5>")
	)
	(segment
		(start 344.57259 -61.513212)
		(end 344.709496 -61.513212)
		(width 0.0889)
		(layer "F.Cu")
		(net "DMI_CPU0_PCH_TX_C_DN<5>")
	)
	(segment
		(start 346.908374 -63.514224)
		(end 347.237812 -63.734188)
		(width 0.13208)
		(layer "F.Cu")
		(net "DMI_CPU0_PCH_TX_C_DN<5>")
	)
	(segment
		(start 343.40292 -59.686952)
		(end 343.49944 -59.783472)
		(width 0.0889)
		(layer "F.Cu")
		(net "DMI_CPU0_PCH_TX_C_DN<5>")
	)
	(segment
		(start 343.40292 -60.235592)
		(end 343.64041 -60.473082)
		(width 0.0889)
		(layer "F.Cu")
		(net "DMI_CPU0_PCH_TX_C_DN<5>")
	)
	(segment
		(start 349.89135 -64.780922)
		(end 350.013016 -64.902588)
		(width 0.13208)
		(layer "F.Cu")
		(net "DMI_CPU0_PCH_TX_C_DN<5>")
	)
	(segment
		(start 346.37599 -63.15837)
		(end 346.5449 -63.124842)
		(width 0.13208)
		(layer "F.Cu")
		(net "DMI_CPU0_PCH_TX_C_DN<5>")
	)
	(segment
		(start 349.494602 -64.780922)
		(end 349.89135 -64.780922)
		(width 0.13208)
		(layer "F.Cu")
		(net "DMI_CPU0_PCH_TX_C_DN<5>")
	)
	(segment
		(start 344.835226 -61.638942)
		(end 344.835226 -61.775848)
		(width 0.0889)
		(layer "F.Cu")
		(net "DMI_CPU0_PCH_TX_C_DN<5>")
	)
	(segment
		(start 344.709496 -61.513212)
		(end 344.835226 -61.638942)
		(width 0.0889)
		(layer "F.Cu")
		(net "DMI_CPU0_PCH_TX_C_DN<5>")
	)
	(segment
		(start 344.321384 -61.1251)
		(end 344.447114 -61.25083)
		(width 0.0889)
		(layer "F.Cu")
		(net "DMI_CPU0_PCH_TX_C_DN<5>")
	)
	(segment
		(start 345.901518 -62.84214)
		(end 345.950286 -62.84214)
		(width 0.0889)
		(layer "F.Cu")
		(net "DMI_CPU0_PCH_TX_C_DN<5>")
	)
	(segment
		(start 345.48572 -62.289436)
		(end 345.61145 -62.415166)
		(width 0.0889)
		(layer "F.Cu")
		(net "DMI_CPU0_PCH_TX_C_DN<5>")
	)
	(segment
		(start 344.447114 -61.25083)
		(end 344.447114 -61.387736)
		(width 0.0889)
		(layer "F.Cu")
		(net "DMI_CPU0_PCH_TX_C_DN<5>")
	)
	(segment
		(start 344.059002 -60.999624)
		(end 344.184478 -61.1251)
		(width 0.0889)
		(layer "F.Cu")
		(net "DMI_CPU0_PCH_TX_C_DN<5>")
	)
	(segment
		(start 348.63405 -64.667638)
		(end 348.985586 -64.902588)
		(width 0.13208)
		(layer "F.Cu")
		(net "DMI_CPU0_PCH_TX_C_DN<5>")
	)
	(segment
		(start 344.960702 -61.901324)
		(end 345.097608 -61.901324)
		(width 0.0889)
		(layer "F.Cu")
		(net "DMI_CPU0_PCH_TX_C_DN<5>")
	)
	(segment
		(start 343.64041 -60.473082)
		(end 343.777316 -60.473082)
		(width 0.0889)
		(layer "F.Cu")
		(net "DMI_CPU0_PCH_TX_C_DN<5>")
	)
	(segment
		(start 347.770196 -64.090296)
		(end 348.099634 -64.31026)
		(width 0.13208)
		(layer "F.Cu")
		(net "DMI_CPU0_PCH_TX_C_DN<5>")
	)
	(segment
		(start 344.447114 -61.387736)
		(end 344.57259 -61.513212)
		(width 0.0889)
		(layer "F.Cu")
		(net "DMI_CPU0_PCH_TX_C_DN<5>")
	)
	(segment
		(start 344.059002 -60.891674)
		(end 344.059002 -60.999624)
		(width 0.0889)
		(layer "F.Cu")
		(net "DMI_CPU0_PCH_TX_C_DN<5>")
	)
	(segment
		(start 346.874592 -63.345314)
		(end 346.908374 -63.514224)
		(width 0.13208)
		(layer "F.Cu")
		(net "DMI_CPU0_PCH_TX_C_DN<5>")
	)
	(segment
		(start 346.5449 -63.124842)
		(end 346.874592 -63.345314)
		(width 0.13208)
		(layer "F.Cu")
		(net "DMI_CPU0_PCH_TX_C_DN<5>")
	)
	(segment
		(start 347.237812 -63.734188)
		(end 347.406722 -63.70066)
		(width 0.13208)
		(layer "F.Cu")
		(net "DMI_CPU0_PCH_TX_C_DN<5>")
	)
	(segment
		(start 343.777316 -60.473082)
		(end 343.903046 -60.598812)
		(width 0.0889)
		(layer "F.Cu")
		(net "DMI_CPU0_PCH_TX_C_DN<5>")
	)
	(segment
		(start 345.223338 -62.027054)
		(end 345.223338 -62.16396)
		(width 0.0889)
		(layer "F.Cu")
		(net "DMI_CPU0_PCH_TX_C_DN<5>")
	)
	(segment
		(start 349.372936 -64.902588)
		(end 349.494602 -64.780922)
		(width 0.13208)
		(layer "F.Cu")
		(net "DMI_CPU0_PCH_TX_C_DN<5>")
	)
	(segment
		(start 345.348814 -62.289436)
		(end 345.48572 -62.289436)
		(width 0.0889)
		(layer "F.Cu")
		(net "DMI_CPU0_PCH_TX_C_DN<5>")
	)
	(segment
		(start 347.736414 -63.921132)
		(end 347.770196 -64.090296)
		(width 0.13208)
		(layer "F.Cu")
		(net "DMI_CPU0_PCH_TX_C_DN<5>")
	)
	(segment
		(start 345.61145 -62.552072)
		(end 345.901518 -62.84214)
		(width 0.0889)
		(layer "F.Cu")
		(net "DMI_CPU0_PCH_TX_C_DN<5>")
	)
	(segment
		(start 343.40292 -58.850276)
		(end 343.40292 -59.686952)
		(width 0.0889)
		(layer "F.Cu")
		(net "DMI_CPU0_PCH_TX_C_DN<5>")
	)
	(segment
		(start 351.27692 -64.902588)
		(end 351.409 -64.770508)
		(width 0.13208)
		(layer "F.Cu")
		(net "DMI_CPU0_PCH_TX_C_DN<5>")
	)
	(segment
		(start 343.49944 -59.961272)
		(end 343.40292 -60.057792)
		(width 0.0889)
		(layer "F.Cu")
		(net "DMI_CPU0_PCH_TX_C_DN<5>")
	)
	(segment
		(start 351.409 -64.770508)
		(end 351.409 -64.440562)
		(width 0.13208)
		(layer "F.Cu")
		(net "DMI_CPU0_PCH_TX_C_DN<5>")
	)
	(segment
		(start 345.96578 -62.857634)
		(end 346.046552 -62.938406)
		(width 0.13208)
		(layer "F.Cu")
		(net "DMI_CPU0_PCH_TX_C_DN<5>")
	)
	(segment
		(start 348.575376 -66.571368)
		(end 348.695264 -66.45148)
		(width 0.13208)
		(layer "F.Cu")
		(net "DMI_CPU0_PCH_TX_C_DN<4>")
	)
	(segment
		(start 342.90254 -59.265312)
		(end 342.90254 -59.435746)
		(width 0.0889)
		(layer "F.Cu")
		(net "DMI_CPU0_PCH_TX_C_DN<4>")
	)
	(segment
		(start 343.00414 -60.213494)
		(end 342.90254 -60.315094)
		(width 0.0889)
		(layer "F.Cu")
		(net "DMI_CPU0_PCH_TX_C_DN<4>")
	)
	(segment
		(start 343.490804 -61.926978)
		(end 343.76741 -62.203584)
		(width 0.13208)
		(layer "F.Cu")
		(net "DMI_CPU0_PCH_TX_C_DN<4>")
	)
	(segment
		(start 344.209624 -62.645798)
		(end 344.478864 -62.915038)
		(width 0.13208)
		(layer "F.Cu")
		(net "DMI_CPU0_PCH_TX_C_DN<4>")
	)
	(segment
		(start 342.90254 -59.435746)
		(end 343.00414 -59.537346)
		(width 0.0889)
		(layer "F.Cu")
		(net "DMI_CPU0_PCH_TX_C_DN<4>")
	)
	(segment
		(start 348.695264 -66.45148)
		(end 348.695264 -66.074544)
		(width 0.13208)
		(layer "F.Cu")
		(net "DMI_CPU0_PCH_TX_C_DN<4>")
	)
	(segment
		(start 347.05544 -65.319148)
		(end 347.05544 -65.491614)
		(width 0.13208)
		(layer "F.Cu")
		(net "DMI_CPU0_PCH_TX_C_DN<4>")
	)
	(segment
		(start 346.343986 -64.78016)
		(end 346.613226 -65.0494)
		(width 0.13208)
		(layer "F.Cu")
		(net "DMI_CPU0_PCH_TX_C_DN<4>")
	)
	(segment
		(start 342.90254 -59.791346)
		(end 342.90254 -59.959494)
		(width 0.0889)
		(layer "F.Cu")
		(net "DMI_CPU0_PCH_TX_C_DN<4>")
	)
	(segment
		(start 343.45753 -61.250068)
		(end 343.55659 -61.349128)
		(width 0.0889)
		(layer "F.Cu")
		(net "DMI_CPU0_PCH_TX_C_DN<4>")
	)
	(segment
		(start 347.32468 -65.760854)
		(end 347.497146 -65.760854)
		(width 0.13208)
		(layer "F.Cu")
		(net "DMI_CPU0_PCH_TX_C_DN<4>")
	)
	(segment
		(start 343.55659 -61.349128)
		(end 343.55659 -61.501528)
		(width 0.0889)
		(layer "F.Cu")
		(net "DMI_CPU0_PCH_TX_C_DN<4>")
	)
	(segment
		(start 344.65133 -62.915038)
		(end 344.921078 -63.184786)
		(width 0.13208)
		(layer "F.Cu")
		(net "DMI_CPU0_PCH_TX_C_DN<4>")
	)
	(segment
		(start 345.632532 -64.068706)
		(end 345.901772 -64.337946)
		(width 0.13208)
		(layer "F.Cu")
		(net "DMI_CPU0_PCH_TX_C_DN<4>")
	)
	(segment
		(start 343.45753 -61.764164)
		(end 343.493344 -61.799978)
		(width 0.0889)
		(layer "F.Cu")
		(net "DMI_CPU0_PCH_TX_C_DN<4>")
	)
	(segment
		(start 344.478864 -62.915038)
		(end 344.65133 -62.915038)
		(width 0.13208)
		(layer "F.Cu")
		(net "DMI_CPU0_PCH_TX_C_DN<4>")
	)
	(segment
		(start 344.921078 -63.357252)
		(end 345.190318 -63.626492)
		(width 0.13208)
		(layer "F.Cu")
		(net "DMI_CPU0_PCH_TX_C_DN<4>")
	)
	(segment
		(start 346.613226 -65.0494)
		(end 346.785692 -65.0494)
		(width 0.13208)
		(layer "F.Cu")
		(net "DMI_CPU0_PCH_TX_C_DN<4>")
	)
	(segment
		(start 343.76741 -62.203584)
		(end 343.939876 -62.203584)
		(width 0.13208)
		(layer "F.Cu")
		(net "DMI_CPU0_PCH_TX_C_DN<4>")
	)
	(segment
		(start 345.632532 -63.89624)
		(end 345.632532 -64.068706)
		(width 0.13208)
		(layer "F.Cu")
		(net "DMI_CPU0_PCH_TX_C_DN<4>")
	)
	(segment
		(start 344.921078 -63.184786)
		(end 344.921078 -63.357252)
		(width 0.13208)
		(layer "F.Cu")
		(net "DMI_CPU0_PCH_TX_C_DN<4>")
	)
	(segment
		(start 345.362784 -63.626492)
		(end 345.632532 -63.89624)
		(width 0.13208)
		(layer "F.Cu")
		(net "DMI_CPU0_PCH_TX_C_DN<4>")
	)
	(segment
		(start 343.00414 -59.689746)
		(end 342.90254 -59.791346)
		(width 0.0889)
		(layer "F.Cu")
		(net "DMI_CPU0_PCH_TX_C_DN<4>")
	)
	(segment
		(start 347.766894 -66.030602)
		(end 347.766894 -66.203068)
		(width 0.13208)
		(layer "F.Cu")
		(net "DMI_CPU0_PCH_TX_C_DN<4>")
	)
	(segment
		(start 347.497146 -65.760854)
		(end 347.766894 -66.030602)
		(width 0.13208)
		(layer "F.Cu")
		(net "DMI_CPU0_PCH_TX_C_DN<4>")
	)
	(segment
		(start 347.766894 -66.203068)
		(end 348.135194 -66.571368)
		(width 0.13208)
		(layer "F.Cu")
		(net "DMI_CPU0_PCH_TX_C_DN<4>")
	)
	(segment
		(start 345.190318 -63.626492)
		(end 345.362784 -63.626492)
		(width 0.13208)
		(layer "F.Cu")
		(net "DMI_CPU0_PCH_TX_C_DN<4>")
	)
	(segment
		(start 343.20099 -60.673742)
		(end 343.308686 -60.781438)
		(width 0.0889)
		(layer "F.Cu")
		(net "DMI_CPU0_PCH_TX_C_DN<4>")
	)
	(segment
		(start 346.074238 -64.337946)
		(end 346.343986 -64.607694)
		(width 0.13208)
		(layer "F.Cu")
		(net "DMI_CPU0_PCH_TX_C_DN<4>")
	)
	(segment
		(start 343.493344 -61.819536)
		(end 343.490804 -61.822076)
		(width 0.0889)
		(layer "F.Cu")
		(net "DMI_CPU0_PCH_TX_C_DN<4>")
	)
	(segment
		(start 344.209624 -62.473332)
		(end 344.209624 -62.645798)
		(width 0.13208)
		(layer "F.Cu")
		(net "DMI_CPU0_PCH_TX_C_DN<4>")
	)
	(segment
		(start 343.490804 -61.822076)
		(end 343.490804 -61.926978)
		(width 0.13208)
		(layer "F.Cu")
		(net "DMI_CPU0_PCH_TX_C_DN<4>")
	)
	(segment
		(start 343.493344 -61.799978)
		(end 343.493344 -61.819536)
		(width 0.0889)
		(layer "F.Cu")
		(net "DMI_CPU0_PCH_TX_C_DN<4>")
	)
	(segment
		(start 343.45753 -61.600588)
		(end 343.45753 -61.764164)
		(width 0.0889)
		(layer "F.Cu")
		(net "DMI_CPU0_PCH_TX_C_DN<4>")
	)
	(segment
		(start 342.90254 -59.959494)
		(end 343.00414 -60.061094)
		(width 0.0889)
		(layer "F.Cu")
		(net "DMI_CPU0_PCH_TX_C_DN<4>")
	)
	(segment
		(start 342.90254 -60.315094)
		(end 342.90254 -60.515754)
		(width 0.0889)
		(layer "F.Cu")
		(net "DMI_CPU0_PCH_TX_C_DN<4>")
	)
	(segment
		(start 343.060528 -60.673742)
		(end 343.20099 -60.673742)
		(width 0.0889)
		(layer "F.Cu")
		(net "DMI_CPU0_PCH_TX_C_DN<4>")
	)
	(segment
		(start 347.05544 -65.491614)
		(end 347.32468 -65.760854)
		(width 0.13208)
		(layer "F.Cu")
		(net "DMI_CPU0_PCH_TX_C_DN<4>")
	)
	(segment
		(start 343.55659 -61.501528)
		(end 343.45753 -61.600588)
		(width 0.0889)
		(layer "F.Cu")
		(net "DMI_CPU0_PCH_TX_C_DN<4>")
	)
	(segment
		(start 343.00414 -60.061094)
		(end 343.00414 -60.213494)
		(width 0.0889)
		(layer "F.Cu")
		(net "DMI_CPU0_PCH_TX_C_DN<4>")
	)
	(segment
		(start 342.90254 -60.515754)
		(end 343.060528 -60.673742)
		(width 0.0889)
		(layer "F.Cu")
		(net "DMI_CPU0_PCH_TX_C_DN<4>")
	)
	(segment
		(start 343.308686 -60.9219)
		(end 343.45753 -61.070744)
		(width 0.0889)
		(layer "F.Cu")
		(net "DMI_CPU0_PCH_TX_C_DN<4>")
	)
	(segment
		(start 348.135194 -66.571368)
		(end 348.575376 -66.571368)
		(width 0.13208)
		(layer "F.Cu")
		(net "DMI_CPU0_PCH_TX_C_DN<4>")
	)
	(segment
		(start 346.343986 -64.607694)
		(end 346.343986 -64.78016)
		(width 0.13208)
		(layer "F.Cu")
		(net "DMI_CPU0_PCH_TX_C_DN<4>")
	)
	(segment
		(start 343.00414 -59.537346)
		(end 343.00414 -59.689746)
		(width 0.0889)
		(layer "F.Cu")
		(net "DMI_CPU0_PCH_TX_C_DN<4>")
	)
	(segment
		(start 343.939876 -62.203584)
		(end 344.209624 -62.473332)
		(width 0.13208)
		(layer "F.Cu")
		(net "DMI_CPU0_PCH_TX_C_DN<4>")
	)
	(segment
		(start 346.785692 -65.0494)
		(end 347.05544 -65.319148)
		(width 0.13208)
		(layer "F.Cu")
		(net "DMI_CPU0_PCH_TX_C_DN<4>")
	)
	(segment
		(start 343.45753 -61.070744)
		(end 343.45753 -61.250068)
		(width 0.0889)
		(layer "F.Cu")
		(net "DMI_CPU0_PCH_TX_C_DN<4>")
	)
	(segment
		(start 345.901772 -64.337946)
		(end 346.074238 -64.337946)
		(width 0.13208)
		(layer "F.Cu")
		(net "DMI_CPU0_PCH_TX_C_DN<4>")
	)
	(segment
		(start 343.308686 -60.781438)
		(end 343.308686 -60.9219)
		(width 0.0889)
		(layer "F.Cu")
		(net "DMI_CPU0_PCH_TX_C_DN<4>")
	)
	(segment
		(start 345.68003 -65.827402)
		(end 345.507818 -65.827402)
		(width 0.13208)
		(layer "F.Cu")
		(net "DMI_CPU0_PCH_TX_C_DN<3>")
	)
	(segment
		(start 342.402414 -59.693048)
		(end 342.402414 -58.850276)
		(width 0.0889)
		(layer "F.Cu")
		(net "DMI_CPU0_PCH_TX_C_DN<3>")
	)
	(segment
		(start 342.876632 -61.828426)
		(end 342.777572 -61.729366)
		(width 0.0889)
		(layer "F.Cu")
		(net "DMI_CPU0_PCH_TX_C_DN<3>")
	)
	(segment
		(start 348.747334 -68.21678)
		(end 348.747334 -68.583048)
		(width 0.13208)
		(layer "F.Cu")
		(net "DMI_CPU0_PCH_TX_C_DN<3>")
	)
	(segment
		(start 346.41282 -66.560192)
		(end 346.240608 -66.560192)
		(width 0.13208)
		(layer "F.Cu")
		(net "DMI_CPU0_PCH_TX_C_DN<3>")
	)
	(segment
		(start 342.777572 -61.729366)
		(end 342.777572 -61.576966)
		(width 0.0889)
		(layer "F.Cu")
		(net "DMI_CPU0_PCH_TX_C_DN<3>")
	)
	(segment
		(start 342.501474 -60.447428)
		(end 342.501474 -60.295028)
		(width 0.0889)
		(layer "F.Cu")
		(net "DMI_CPU0_PCH_TX_C_DN<3>")
	)
	(segment
		(start 343.092024 -63.180214)
		(end 342.811862 -62.900052)
		(width 0.13208)
		(layer "F.Cu")
		(net "DMI_CPU0_PCH_TX_C_DN<3>")
	)
	(segment
		(start 346.693236 -67.01282)
		(end 346.693236 -66.840608)
		(width 0.13208)
		(layer "F.Cu")
		(net "DMI_CPU0_PCH_TX_C_DN<3>")
	)
	(segment
		(start 343.544652 -63.46063)
		(end 343.264236 -63.180214)
		(width 0.13208)
		(layer "F.Cu")
		(net "DMI_CPU0_PCH_TX_C_DN<3>")
	)
	(segment
		(start 345.227656 -65.315846)
		(end 345.010232 -65.098422)
		(width 0.13208)
		(layer "F.Cu")
		(net "DMI_CPU0_PCH_TX_C_DN<3>")
	)
	(segment
		(start 345.227656 -65.54724)
		(end 345.227656 -65.315846)
		(width 0.13208)
		(layer "F.Cu")
		(net "DMI_CPU0_PCH_TX_C_DN<3>")
	)
	(segment
		(start 344.729816 -64.645794)
		(end 344.557604 -64.645794)
		(width 0.13208)
		(layer "F.Cu")
		(net "DMI_CPU0_PCH_TX_C_DN<3>")
	)
	(segment
		(start 348.615254 -68.715128)
		(end 348.395544 -68.715128)
		(width 0.13208)
		(layer "F.Cu")
		(net "DMI_CPU0_PCH_TX_C_DN<3>")
	)
	(segment
		(start 347.426026 -67.74561)
		(end 347.426026 -67.573398)
		(width 0.13208)
		(layer "F.Cu")
		(net "DMI_CPU0_PCH_TX_C_DN<3>")
	)
	(segment
		(start 345.960446 -66.28003)
		(end 345.960446 -66.107818)
		(width 0.13208)
		(layer "F.Cu")
		(net "DMI_CPU0_PCH_TX_C_DN<3>")
	)
	(segment
		(start 342.402414 -60.195968)
		(end 342.402414 -60.043568)
		(width 0.0889)
		(layer "F.Cu")
		(net "DMI_CPU0_PCH_TX_C_DN<3>")
	)
	(segment
		(start 342.402414 -60.780676)
		(end 342.402414 -60.546488)
		(width 0.0889)
		(layer "F.Cu")
		(net "DMI_CPU0_PCH_TX_C_DN<3>")
	)
	(segment
		(start 348.395544 -68.715128)
		(end 347.426026 -67.74561)
		(width 0.13208)
		(layer "F.Cu")
		(net "DMI_CPU0_PCH_TX_C_DN<3>")
	)
	(segment
		(start 342.501474 -59.792108)
		(end 342.402414 -59.693048)
		(width 0.0889)
		(layer "F.Cu")
		(net "DMI_CPU0_PCH_TX_C_DN<3>")
	)
	(segment
		(start 345.960446 -66.107818)
		(end 345.68003 -65.827402)
		(width 0.13208)
		(layer "F.Cu")
		(net "DMI_CPU0_PCH_TX_C_DN<3>")
	)
	(segment
		(start 342.777572 -61.155834)
		(end 342.402414 -60.780676)
		(width 0.0889)
		(layer "F.Cu")
		(net "DMI_CPU0_PCH_TX_C_DN<3>")
	)
	(segment
		(start 345.010232 -65.098422)
		(end 345.010232 -64.92621)
		(width 0.13208)
		(layer "F.Cu")
		(net "DMI_CPU0_PCH_TX_C_DN<3>")
	)
	(segment
		(start 342.777572 -61.576966)
		(end 342.876632 -61.477906)
		(width 0.0889)
		(layer "F.Cu")
		(net "DMI_CPU0_PCH_TX_C_DN<3>")
	)
	(segment
		(start 342.402414 -60.043568)
		(end 342.501474 -59.944508)
		(width 0.0889)
		(layer "F.Cu")
		(net "DMI_CPU0_PCH_TX_C_DN<3>")
	)
	(segment
		(start 342.811862 -62.652148)
		(end 342.777572 -62.617858)
		(width 0.0889)
		(layer "F.Cu")
		(net "DMI_CPU0_PCH_TX_C_DN<3>")
	)
	(segment
		(start 342.876632 -61.325506)
		(end 342.777572 -61.226446)
		(width 0.0889)
		(layer "F.Cu")
		(net "DMI_CPU0_PCH_TX_C_DN<3>")
	)
	(segment
		(start 346.693236 -66.840608)
		(end 346.41282 -66.560192)
		(width 0.13208)
		(layer "F.Cu")
		(net "DMI_CPU0_PCH_TX_C_DN<3>")
	)
	(segment
		(start 347.14561 -67.292982)
		(end 346.973398 -67.292982)
		(width 0.13208)
		(layer "F.Cu")
		(net "DMI_CPU0_PCH_TX_C_DN<3>")
	)
	(segment
		(start 342.777572 -62.617858)
		(end 342.777572 -62.079886)
		(width 0.0889)
		(layer "F.Cu")
		(net "DMI_CPU0_PCH_TX_C_DN<3>")
	)
	(segment
		(start 347.426026 -67.573398)
		(end 347.14561 -67.292982)
		(width 0.13208)
		(layer "F.Cu")
		(net "DMI_CPU0_PCH_TX_C_DN<3>")
	)
	(segment
		(start 343.264236 -63.180214)
		(end 343.092024 -63.180214)
		(width 0.13208)
		(layer "F.Cu")
		(net "DMI_CPU0_PCH_TX_C_DN<3>")
	)
	(segment
		(start 342.777572 -62.079886)
		(end 342.876632 -61.980826)
		(width 0.0889)
		(layer "F.Cu")
		(net "DMI_CPU0_PCH_TX_C_DN<3>")
	)
	(segment
		(start 348.747334 -68.583048)
		(end 348.615254 -68.715128)
		(width 0.13208)
		(layer "F.Cu")
		(net "DMI_CPU0_PCH_TX_C_DN<3>")
	)
	(segment
		(start 342.876632 -61.477906)
		(end 342.876632 -61.325506)
		(width 0.0889)
		(layer "F.Cu")
		(net "DMI_CPU0_PCH_TX_C_DN<3>")
	)
	(segment
		(start 342.777572 -61.226446)
		(end 342.777572 -61.155834)
		(width 0.0889)
		(layer "F.Cu")
		(net "DMI_CPU0_PCH_TX_C_DN<3>")
	)
	(segment
		(start 344.277442 -64.19342)
		(end 343.997026 -63.913004)
		(width 0.13208)
		(layer "F.Cu")
		(net "DMI_CPU0_PCH_TX_C_DN<3>")
	)
	(segment
		(start 342.501474 -60.295028)
		(end 342.402414 -60.195968)
		(width 0.0889)
		(layer "F.Cu")
		(net "DMI_CPU0_PCH_TX_C_DN<3>")
	)
	(segment
		(start 342.811862 -62.900052)
		(end 342.811862 -62.674246)
		(width 0.13208)
		(layer "F.Cu")
		(net "DMI_CPU0_PCH_TX_C_DN<3>")
	)
	(segment
		(start 342.501474 -59.944508)
		(end 342.501474 -59.792108)
		(width 0.0889)
		(layer "F.Cu")
		(net "DMI_CPU0_PCH_TX_C_DN<3>")
	)
	(segment
		(start 343.997026 -63.913004)
		(end 343.824814 -63.913004)
		(width 0.13208)
		(layer "F.Cu")
		(net "DMI_CPU0_PCH_TX_C_DN<3>")
	)
	(segment
		(start 344.277442 -64.365632)
		(end 344.277442 -64.19342)
		(width 0.13208)
		(layer "F.Cu")
		(net "DMI_CPU0_PCH_TX_C_DN<3>")
	)
	(segment
		(start 343.824814 -63.913004)
		(end 343.544652 -63.632842)
		(width 0.13208)
		(layer "F.Cu")
		(net "DMI_CPU0_PCH_TX_C_DN<3>")
	)
	(segment
		(start 342.876632 -61.980826)
		(end 342.876632 -61.828426)
		(width 0.0889)
		(layer "F.Cu")
		(net "DMI_CPU0_PCH_TX_C_DN<3>")
	)
	(segment
		(start 345.010232 -64.92621)
		(end 344.729816 -64.645794)
		(width 0.13208)
		(layer "F.Cu")
		(net "DMI_CPU0_PCH_TX_C_DN<3>")
	)
	(segment
		(start 346.973398 -67.292982)
		(end 346.693236 -67.01282)
		(width 0.13208)
		(layer "F.Cu")
		(net "DMI_CPU0_PCH_TX_C_DN<3>")
	)
	(segment
		(start 344.557604 -64.645794)
		(end 344.277442 -64.365632)
		(width 0.13208)
		(layer "F.Cu")
		(net "DMI_CPU0_PCH_TX_C_DN<3>")
	)
	(segment
		(start 343.544652 -63.632842)
		(end 343.544652 -63.46063)
		(width 0.13208)
		(layer "F.Cu")
		(net "DMI_CPU0_PCH_TX_C_DN<3>")
	)
	(segment
		(start 342.811862 -62.674246)
		(end 342.811862 -62.652148)
		(width 0.0889)
		(layer "F.Cu")
		(net "DMI_CPU0_PCH_TX_C_DN<3>")
	)
	(segment
		(start 342.402414 -60.546488)
		(end 342.501474 -60.447428)
		(width 0.0889)
		(layer "F.Cu")
		(net "DMI_CPU0_PCH_TX_C_DN<3>")
	)
	(segment
		(start 345.507818 -65.827402)
		(end 345.227656 -65.54724)
		(width 0.13208)
		(layer "F.Cu")
		(net "DMI_CPU0_PCH_TX_C_DN<3>")
	)
	(segment
		(start 346.240608 -66.560192)
		(end 345.960446 -66.28003)
		(width 0.13208)
		(layer "F.Cu")
		(net "DMI_CPU0_PCH_TX_C_DN<3>")
	)
	(segment
		(start 343.79281 -64.957706)
		(end 343.652602 -64.957706)
		(width 0.0889)
		(layer "F.Cu")
		(net "DMI_CPU0_PCH_TX_C_DN<2>")
	)
	(segment
		(start 342.22055 -62.013084)
		(end 342.22055 -61.860684)
		(width 0.0889)
		(layer "F.Cu")
		(net "DMI_CPU0_PCH_TX_C_DN<2>")
	)
	(segment
		(start 342.12149 -63.426594)
		(end 342.12149 -63.117984)
		(width 0.0889)
		(layer "F.Cu")
		(net "DMI_CPU0_PCH_TX_C_DN<2>")
	)
	(segment
		(start 342.833198 -63.99784)
		(end 342.725248 -63.890144)
		(width 0.0889)
		(layer "F.Cu")
		(net "DMI_CPU0_PCH_TX_C_DN<2>")
	)
	(segment
		(start 344.284554 -67.146424)
		(end 344.284554 -66.268346)
		(width 0.13208)
		(layer "F.Cu")
		(net "DMI_CPU0_PCH_TX_C_DN<2>")
	)
	(segment
		(start 342.833198 -64.138302)
		(end 342.833198 -63.99784)
		(width 0.0889)
		(layer "F.Cu")
		(net "DMI_CPU0_PCH_TX_C_DN<2>")
	)
	(segment
		(start 342.12149 -63.117984)
		(end 342.22055 -63.018924)
		(width 0.0889)
		(layer "F.Cu")
		(net "DMI_CPU0_PCH_TX_C_DN<2>")
	)
	(segment
		(start 341.784432 -60.560966)
		(end 341.883492 -60.461906)
		(width 0.0889)
		(layer "F.Cu")
		(net "DMI_CPU0_PCH_TX_C_DN<2>")
	)
	(segment
		(start 342.22055 -62.516004)
		(end 342.22055 -62.363604)
		(width 0.0889)
		(layer "F.Cu")
		(net "DMI_CPU0_PCH_TX_C_DN<2>")
	)
	(segment
		(start 342.22055 -61.357764)
		(end 342.12149 -61.258704)
		(width 0.0889)
		(layer "F.Cu")
		(net "DMI_CPU0_PCH_TX_C_DN<2>")
	)
	(segment
		(start 342.229186 -63.53429)
		(end 342.12149 -63.426594)
		(width 0.0889)
		(layer "F.Cu")
		(net "DMI_CPU0_PCH_TX_C_DN<2>")
	)
	(segment
		(start 342.940894 -64.245998)
		(end 342.833198 -64.138302)
		(width 0.0889)
		(layer "F.Cu")
		(net "DMI_CPU0_PCH_TX_C_DN<2>")
	)
	(segment
		(start 343.544906 -64.709548)
		(end 343.436956 -64.601852)
		(width 0.0889)
		(layer "F.Cu")
		(net "DMI_CPU0_PCH_TX_C_DN<2>")
	)
	(segment
		(start 342.12149 -62.112144)
		(end 342.22055 -62.013084)
		(width 0.0889)
		(layer "F.Cu")
		(net "DMI_CPU0_PCH_TX_C_DN<2>")
	)
	(segment
		(start 341.784432 -60.210446)
		(end 341.784432 -60.058046)
		(width 0.0889)
		(layer "F.Cu")
		(net "DMI_CPU0_PCH_TX_C_DN<2>")
	)
	(segment
		(start 341.784432 -60.713366)
		(end 341.784432 -60.560966)
		(width 0.0889)
		(layer "F.Cu")
		(net "DMI_CPU0_PCH_TX_C_DN<2>")
	)
	(segment
		(start 342.12149 -61.258704)
		(end 342.12149 -61.050424)
		(width 0.0889)
		(layer "F.Cu")
		(net "DMI_CPU0_PCH_TX_C_DN<2>")
	)
	(segment
		(start 342.369394 -63.53429)
		(end 342.229186 -63.53429)
		(width 0.0889)
		(layer "F.Cu")
		(net "DMI_CPU0_PCH_TX_C_DN<2>")
	)
	(segment
		(start 346.70619 -69.10324)
		(end 346.375736 -68.772786)
		(width 0.13208)
		(layer "F.Cu")
		(net "DMI_CPU0_PCH_TX_C_DN<2>")
	)
	(segment
		(start 346.375736 -68.772786)
		(end 346.375736 -68.410582)
		(width 0.13208)
		(layer "F.Cu")
		(net "DMI_CPU0_PCH_TX_C_DN<2>")
	)
	(segment
		(start 341.784432 -59.382914)
		(end 341.902034 -59.265312)
		(width 0.0889)
		(layer "F.Cu")
		(net "DMI_CPU0_PCH_TX_C_DN<2>")
	)
	(segment
		(start 343.90076 -65.205864)
		(end 343.90076 -65.065402)
		(width 0.0889)
		(layer "F.Cu")
		(net "DMI_CPU0_PCH_TX_C_DN<2>")
	)
	(segment
		(start 343.189052 -64.353694)
		(end 343.081102 -64.245998)
		(width 0.0889)
		(layer "F.Cu")
		(net "DMI_CPU0_PCH_TX_C_DN<2>")
	)
	(segment
		(start 343.90076 -65.065402)
		(end 343.79281 -64.957706)
		(width 0.0889)
		(layer "F.Cu")
		(net "DMI_CPU0_PCH_TX_C_DN<2>")
	)
	(segment
		(start 341.883492 -59.958986)
		(end 341.883492 -59.806586)
		(width 0.0889)
		(layer "F.Cu")
		(net "DMI_CPU0_PCH_TX_C_DN<2>")
	)
	(segment
		(start 345.053158 -67.915028)
		(end 344.284554 -67.146424)
		(width 0.13208)
		(layer "F.Cu")
		(net "DMI_CPU0_PCH_TX_C_DN<2>")
	)
	(segment
		(start 342.477344 -63.782448)
		(end 342.477344 -63.641986)
		(width 0.0889)
		(layer "F.Cu")
		(net "DMI_CPU0_PCH_TX_C_DN<2>")
	)
	(segment
		(start 341.784432 -60.058046)
		(end 341.883492 -59.958986)
		(width 0.0889)
		(layer "F.Cu")
		(net "DMI_CPU0_PCH_TX_C_DN<2>")
	)
	(segment
		(start 341.784432 -59.707526)
		(end 341.784432 -59.382914)
		(width 0.0889)
		(layer "F.Cu")
		(net "DMI_CPU0_PCH_TX_C_DN<2>")
	)
	(segment
		(start 345.880182 -67.915028)
		(end 345.053158 -67.915028)
		(width 0.13208)
		(layer "F.Cu")
		(net "DMI_CPU0_PCH_TX_C_DN<2>")
	)
	(segment
		(start 342.22055 -62.363604)
		(end 342.12149 -62.264544)
		(width 0.0889)
		(layer "F.Cu")
		(net "DMI_CPU0_PCH_TX_C_DN<2>")
	)
	(segment
		(start 342.22055 -61.510164)
		(end 342.22055 -61.357764)
		(width 0.0889)
		(layer "F.Cu")
		(net "DMI_CPU0_PCH_TX_C_DN<2>")
	)
	(segment
		(start 343.296748 -64.601852)
		(end 343.189052 -64.494156)
		(width 0.0889)
		(layer "F.Cu")
		(net "DMI_CPU0_PCH_TX_C_DN<2>")
	)
	(segment
		(start 342.725248 -63.890144)
		(end 342.58504 -63.890144)
		(width 0.0889)
		(layer "F.Cu")
		(net "DMI_CPU0_PCH_TX_C_DN<2>")
	)
	(segment
		(start 343.436956 -64.601852)
		(end 343.296748 -64.601852)
		(width 0.0889)
		(layer "F.Cu")
		(net "DMI_CPU0_PCH_TX_C_DN<2>")
	)
	(segment
		(start 342.12149 -61.609224)
		(end 342.22055 -61.510164)
		(width 0.0889)
		(layer "F.Cu")
		(net "DMI_CPU0_PCH_TX_C_DN<2>")
	)
	(segment
		(start 342.22055 -61.860684)
		(end 342.12149 -61.761624)
		(width 0.0889)
		(layer "F.Cu")
		(net "DMI_CPU0_PCH_TX_C_DN<2>")
	)
	(segment
		(start 342.12149 -61.761624)
		(end 342.12149 -61.609224)
		(width 0.0889)
		(layer "F.Cu")
		(net "DMI_CPU0_PCH_TX_C_DN<2>")
	)
	(segment
		(start 342.22055 -62.866524)
		(end 342.12149 -62.767464)
		(width 0.0889)
		(layer "F.Cu")
		(net "DMI_CPU0_PCH_TX_C_DN<2>")
	)
	(segment
		(start 342.12149 -62.615064)
		(end 342.22055 -62.516004)
		(width 0.0889)
		(layer "F.Cu")
		(net "DMI_CPU0_PCH_TX_C_DN<2>")
	)
	(segment
		(start 341.883492 -59.806586)
		(end 341.784432 -59.707526)
		(width 0.0889)
		(layer "F.Cu")
		(net "DMI_CPU0_PCH_TX_C_DN<2>")
	)
	(segment
		(start 342.22055 -63.018924)
		(end 342.22055 -62.866524)
		(width 0.0889)
		(layer "F.Cu")
		(net "DMI_CPU0_PCH_TX_C_DN<2>")
	)
	(segment
		(start 344.284554 -66.268346)
		(end 344.284554 -66.246248)
		(width 0.0889)
		(layer "F.Cu")
		(net "DMI_CPU0_PCH_TX_C_DN<2>")
	)
	(segment
		(start 344.250264 -65.555368)
		(end 343.90076 -65.205864)
		(width 0.0889)
		(layer "F.Cu")
		(net "DMI_CPU0_PCH_TX_C_DN<2>")
	)
	(segment
		(start 342.477344 -63.641986)
		(end 342.369394 -63.53429)
		(width 0.0889)
		(layer "F.Cu")
		(net "DMI_CPU0_PCH_TX_C_DN<2>")
	)
	(segment
		(start 343.189052 -64.494156)
		(end 343.189052 -64.353694)
		(width 0.0889)
		(layer "F.Cu")
		(net "DMI_CPU0_PCH_TX_C_DN<2>")
	)
	(segment
		(start 343.544906 -64.85001)
		(end 343.544906 -64.709548)
		(width 0.0889)
		(layer "F.Cu")
		(net "DMI_CPU0_PCH_TX_C_DN<2>")
	)
	(segment
		(start 341.883492 -60.461906)
		(end 341.883492 -60.309506)
		(width 0.0889)
		(layer "F.Cu")
		(net "DMI_CPU0_PCH_TX_C_DN<2>")
	)
	(segment
		(start 341.883492 -60.309506)
		(end 341.784432 -60.210446)
		(width 0.0889)
		(layer "F.Cu")
		(net "DMI_CPU0_PCH_TX_C_DN<2>")
	)
	(segment
		(start 342.12149 -62.264544)
		(end 342.12149 -62.112144)
		(width 0.0889)
		(layer "F.Cu")
		(net "DMI_CPU0_PCH_TX_C_DN<2>")
	)
	(segment
		(start 343.652602 -64.957706)
		(end 343.544906 -64.85001)
		(width 0.0889)
		(layer "F.Cu")
		(net "DMI_CPU0_PCH_TX_C_DN<2>")
	)
	(segment
		(start 344.284554 -66.246248)
		(end 344.250264 -66.211958)
		(width 0.0889)
		(layer "F.Cu")
		(net "DMI_CPU0_PCH_TX_C_DN<2>")
	)
	(segment
		(start 344.250264 -66.211958)
		(end 344.250264 -65.555368)
		(width 0.0889)
		(layer "F.Cu")
		(net "DMI_CPU0_PCH_TX_C_DN<2>")
	)
	(segment
		(start 342.12149 -62.767464)
		(end 342.12149 -62.615064)
		(width 0.0889)
		(layer "F.Cu")
		(net "DMI_CPU0_PCH_TX_C_DN<2>")
	)
	(segment
		(start 342.58504 -63.890144)
		(end 342.477344 -63.782448)
		(width 0.0889)
		(layer "F.Cu")
		(net "DMI_CPU0_PCH_TX_C_DN<2>")
	)
	(segment
		(start 342.12149 -61.050424)
		(end 341.784432 -60.713366)
		(width 0.0889)
		(layer "F.Cu")
		(net "DMI_CPU0_PCH_TX_C_DN<2>")
	)
	(segment
		(start 346.375736 -68.410582)
		(end 345.880182 -67.915028)
		(width 0.13208)
		(layer "F.Cu")
		(net "DMI_CPU0_PCH_TX_C_DN<2>")
	)
	(segment
		(start 343.081102 -64.245998)
		(end 342.940894 -64.245998)
		(width 0.0889)
		(layer "F.Cu")
		(net "DMI_CPU0_PCH_TX_C_DN<2>")
	)
	(segment
		(start 342.723724 -67.95643)
		(end 342.832436 -68.218812)
		(width 0.13208)
		(layer "F.Cu")
		(net "DMI_CPU0_PCH_TX_C_DN<1>")
	)
	(segment
		(start 341.598758 -62.694058)
		(end 341.598758 -62.846458)
		(width 0.0889)
		(layer "F.Cu")
		(net "DMI_CPU0_PCH_TX_C_DN<1>")
	)
	(segment
		(start 343.499948 -68.714112)
		(end 343.499948 -68.886324)
		(width 0.13208)
		(layer "F.Cu")
		(net "DMI_CPU0_PCH_TX_C_DN<1>")
	)
	(segment
		(start 343.04732 -68.433696)
		(end 343.219532 -68.433696)
		(width 0.13208)
		(layer "F.Cu")
		(net "DMI_CPU0_PCH_TX_C_DN<1>")
	)
	(segment
		(start 341.598758 -61.840618)
		(end 341.697818 -61.939678)
		(width 0.0889)
		(layer "F.Cu")
		(net "DMI_CPU0_PCH_TX_C_DN<1>")
	)
	(segment
		(start 341.401908 -58.850276)
		(end 341.401908 -60.988448)
		(width 0.0889)
		(layer "F.Cu")
		(net "DMI_CPU0_PCH_TX_C_DN<1>")
	)
	(segment
		(start 344.312494 -69.69887)
		(end 344.312494 -69.917564)
		(width 0.13208)
		(layer "F.Cu")
		(net "DMI_CPU0_PCH_TX_C_DN<1>")
	)
	(segment
		(start 341.598758 -64.156844)
		(end 341.730584 -64.28867)
		(width 0.0889)
		(layer "F.Cu")
		(net "DMI_CPU0_PCH_TX_C_DN<1>")
	)
	(segment
		(start 342.189308 -64.747394)
		(end 342.32977 -64.747394)
		(width 0.0889)
		(layer "F.Cu")
		(net "DMI_CPU0_PCH_TX_C_DN<1>")
	)
	(segment
		(start 341.697818 -62.442598)
		(end 341.697818 -62.594998)
		(width 0.0889)
		(layer "F.Cu")
		(net "DMI_CPU0_PCH_TX_C_DN<1>")
	)
	(segment
		(start 344.312494 -69.917564)
		(end 344.64879 -70.25386)
		(width 0.13208)
		(layer "F.Cu")
		(net "DMI_CPU0_PCH_TX_C_DN<1>")
	)
	(segment
		(start 342.845644 -66.126106)
		(end 342.845644 -66.522346)
		(width 0.13208)
		(layer "F.Cu")
		(net "DMI_CPU0_PCH_TX_C_DN<1>")
	)
	(segment
		(start 341.401908 -60.988448)
		(end 341.598758 -61.185298)
		(width 0.0889)
		(layer "F.Cu")
		(net "DMI_CPU0_PCH_TX_C_DN<1>")
	)
	(segment
		(start 342.723724 -65.607946)
		(end 342.723724 -66.004186)
		(width 0.13208)
		(layer "F.Cu")
		(net "DMI_CPU0_PCH_TX_C_DN<1>")
	)
	(segment
		(start 342.832436 -68.218812)
		(end 343.04732 -68.433696)
		(width 0.13208)
		(layer "F.Cu")
		(net "DMI_CPU0_PCH_TX_C_DN<1>")
	)
	(segment
		(start 341.697818 -61.939678)
		(end 341.697818 -62.092078)
		(width 0.0889)
		(layer "F.Cu")
		(net "DMI_CPU0_PCH_TX_C_DN<1>")
	)
	(segment
		(start 341.697818 -62.092078)
		(end 341.598758 -62.191138)
		(width 0.0889)
		(layer "F.Cu")
		(net "DMI_CPU0_PCH_TX_C_DN<1>")
	)
	(segment
		(start 341.730584 -64.28867)
		(end 341.870792 -64.28867)
		(width 0.0889)
		(layer "F.Cu")
		(net "DMI_CPU0_PCH_TX_C_DN<1>")
	)
	(segment
		(start 341.697818 -63.600838)
		(end 341.598758 -63.699898)
		(width 0.0889)
		(layer "F.Cu")
		(net "DMI_CPU0_PCH_TX_C_DN<1>")
	)
	(segment
		(start 341.697818 -63.448438)
		(end 341.697818 -63.600838)
		(width 0.0889)
		(layer "F.Cu")
		(net "DMI_CPU0_PCH_TX_C_DN<1>")
	)
	(segment
		(start 341.978742 -64.39662)
		(end 341.978742 -64.536828)
		(width 0.0889)
		(layer "F.Cu")
		(net "DMI_CPU0_PCH_TX_C_DN<1>")
	)
	(segment
		(start 342.723724 -65.585848)
		(end 342.723724 -65.607946)
		(width 0.0889)
		(layer "F.Cu")
		(net "DMI_CPU0_PCH_TX_C_DN<1>")
	)
	(segment
		(start 342.723724 -67.680586)
		(end 342.723724 -67.95643)
		(width 0.13208)
		(layer "F.Cu")
		(net "DMI_CPU0_PCH_TX_C_DN<1>")
	)
	(segment
		(start 342.723724 -66.644266)
		(end 342.723724 -67.040506)
		(width 0.13208)
		(layer "F.Cu")
		(net "DMI_CPU0_PCH_TX_C_DN<1>")
	)
	(segment
		(start 342.32977 -64.747394)
		(end 342.437466 -64.85509)
		(width 0.0889)
		(layer "F.Cu")
		(net "DMI_CPU0_PCH_TX_C_DN<1>")
	)
	(segment
		(start 341.598758 -61.337698)
		(end 341.697818 -61.436758)
		(width 0.0889)
		(layer "F.Cu")
		(net "DMI_CPU0_PCH_TX_C_DN<1>")
	)
	(segment
		(start 341.598758 -63.196978)
		(end 341.598758 -63.349378)
		(width 0.0889)
		(layer "F.Cu")
		(net "DMI_CPU0_PCH_TX_C_DN<1>")
	)
	(segment
		(start 341.697818 -62.945518)
		(end 341.697818 -63.097918)
		(width 0.0889)
		(layer "F.Cu")
		(net "DMI_CPU0_PCH_TX_C_DN<1>")
	)
	(segment
		(start 342.437466 -64.995552)
		(end 342.689434 -65.24752)
		(width 0.0889)
		(layer "F.Cu")
		(net "DMI_CPU0_PCH_TX_C_DN<1>")
	)
	(segment
		(start 343.219532 -68.433696)
		(end 343.499948 -68.714112)
		(width 0.13208)
		(layer "F.Cu")
		(net "DMI_CPU0_PCH_TX_C_DN<1>")
	)
	(segment
		(start 341.870792 -64.28867)
		(end 341.978742 -64.39662)
		(width 0.0889)
		(layer "F.Cu")
		(net "DMI_CPU0_PCH_TX_C_DN<1>")
	)
	(segment
		(start 342.845644 -67.162426)
		(end 342.845644 -67.558666)
		(width 0.13208)
		(layer "F.Cu")
		(net "DMI_CPU0_PCH_TX_C_DN<1>")
	)
	(segment
		(start 342.723724 -67.040506)
		(end 342.845644 -67.162426)
		(width 0.13208)
		(layer "F.Cu")
		(net "DMI_CPU0_PCH_TX_C_DN<1>")
	)
	(segment
		(start 343.499948 -68.886324)
		(end 344.312494 -69.69887)
		(width 0.13208)
		(layer "F.Cu")
		(net "DMI_CPU0_PCH_TX_C_DN<1>")
	)
	(segment
		(start 342.689434 -65.551558)
		(end 342.723724 -65.585848)
		(width 0.0889)
		(layer "F.Cu")
		(net "DMI_CPU0_PCH_TX_C_DN<1>")
	)
	(segment
		(start 341.598758 -61.185298)
		(end 341.598758 -61.337698)
		(width 0.0889)
		(layer "F.Cu")
		(net "DMI_CPU0_PCH_TX_C_DN<1>")
	)
	(segment
		(start 342.437466 -64.85509)
		(end 342.437466 -64.995552)
		(width 0.0889)
		(layer "F.Cu")
		(net "DMI_CPU0_PCH_TX_C_DN<1>")
	)
	(segment
		(start 342.845644 -67.558666)
		(end 342.723724 -67.680586)
		(width 0.13208)
		(layer "F.Cu")
		(net "DMI_CPU0_PCH_TX_C_DN<1>")
	)
	(segment
		(start 341.598758 -61.688218)
		(end 341.598758 -61.840618)
		(width 0.0889)
		(layer "F.Cu")
		(net "DMI_CPU0_PCH_TX_C_DN<1>")
	)
	(segment
		(start 342.845644 -66.522346)
		(end 342.723724 -66.644266)
		(width 0.13208)
		(layer "F.Cu")
		(net "DMI_CPU0_PCH_TX_C_DN<1>")
	)
	(segment
		(start 341.598758 -62.191138)
		(end 341.598758 -62.343538)
		(width 0.0889)
		(layer "F.Cu")
		(net "DMI_CPU0_PCH_TX_C_DN<1>")
	)
	(segment
		(start 341.598758 -62.343538)
		(end 341.697818 -62.442598)
		(width 0.0889)
		(layer "F.Cu")
		(net "DMI_CPU0_PCH_TX_C_DN<1>")
	)
	(segment
		(start 341.598758 -63.349378)
		(end 341.697818 -63.448438)
		(width 0.0889)
		(layer "F.Cu")
		(net "DMI_CPU0_PCH_TX_C_DN<1>")
	)
	(segment
		(start 341.598758 -63.699898)
		(end 341.598758 -64.156844)
		(width 0.0889)
		(layer "F.Cu")
		(net "DMI_CPU0_PCH_TX_C_DN<1>")
	)
	(segment
		(start 341.697818 -61.436758)
		(end 341.697818 -61.589158)
		(width 0.0889)
		(layer "F.Cu")
		(net "DMI_CPU0_PCH_TX_C_DN<1>")
	)
	(segment
		(start 341.697818 -61.589158)
		(end 341.598758 -61.688218)
		(width 0.0889)
		(layer "F.Cu")
		(net "DMI_CPU0_PCH_TX_C_DN<1>")
	)
	(segment
		(start 341.978742 -64.536828)
		(end 342.189308 -64.747394)
		(width 0.0889)
		(layer "F.Cu")
		(net "DMI_CPU0_PCH_TX_C_DN<1>")
	)
	(segment
		(start 342.689434 -65.24752)
		(end 342.689434 -65.551558)
		(width 0.0889)
		(layer "F.Cu")
		(net "DMI_CPU0_PCH_TX_C_DN<1>")
	)
	(segment
		(start 342.723724 -66.004186)
		(end 342.845644 -66.126106)
		(width 0.13208)
		(layer "F.Cu")
		(net "DMI_CPU0_PCH_TX_C_DN<1>")
	)
	(segment
		(start 341.598758 -62.846458)
		(end 341.697818 -62.945518)
		(width 0.0889)
		(layer "F.Cu")
		(net "DMI_CPU0_PCH_TX_C_DN<1>")
	)
	(segment
		(start 341.697818 -62.594998)
		(end 341.598758 -62.694058)
		(width 0.0889)
		(layer "F.Cu")
		(net "DMI_CPU0_PCH_TX_C_DN<1>")
	)
	(segment
		(start 341.697818 -63.097918)
		(end 341.598758 -63.196978)
		(width 0.0889)
		(layer "F.Cu")
		(net "DMI_CPU0_PCH_TX_C_DN<1>")
	)
	(segment
		(start 340.88324 -60.137294)
		(end 340.88324 -60.289694)
		(width 0.0889)
		(layer "F.Cu")
		(net "DMI_CPU0_PCH_TX_C_DN<0>")
	)
	(segment
		(start 341.11184 -64.258698)
		(end 341.01278 -64.357758)
		(width 0.0889)
		(layer "F.Cu")
		(net "DMI_CPU0_PCH_TX_C_DN<0>")
	)
	(segment
		(start 340.78418 -59.535314)
		(end 340.88324 -59.634374)
		(width 0.0889)
		(layer "F.Cu")
		(net "DMI_CPU0_PCH_TX_C_DN<0>")
	)
	(segment
		(start 340.78418 -59.885834)
		(end 340.78418 -60.038234)
		(width 0.0889)
		(layer "F.Cu")
		(net "DMI_CPU0_PCH_TX_C_DN<0>")
	)
	(segment
		(start 341.01278 -61.843158)
		(end 341.01278 -61.995558)
		(width 0.0889)
		(layer "F.Cu")
		(net "DMI_CPU0_PCH_TX_C_DN<0>")
	)
	(segment
		(start 341.01278 -62.848998)
		(end 341.01278 -63.001398)
		(width 0.0889)
		(layer "F.Cu")
		(net "DMI_CPU0_PCH_TX_C_DN<0>")
	)
	(segment
		(start 341.11184 -63.252858)
		(end 341.01278 -63.351918)
		(width 0.0889)
		(layer "F.Cu")
		(net "DMI_CPU0_PCH_TX_C_DN<0>")
	)
	(segment
		(start 340.783926 -61.081158)
		(end 341.01278 -61.310012)
		(width 0.0889)
		(layer "F.Cu")
		(net "DMI_CPU0_PCH_TX_C_DN<0>")
	)
	(segment
		(start 340.901782 -59.265312)
		(end 340.78418 -59.382914)
		(width 0.0889)
		(layer "F.Cu")
		(net "DMI_CPU0_PCH_TX_C_DN<0>")
	)
	(segment
		(start 341.691976 -67.216528)
		(end 341.570056 -67.338448)
		(width 0.13208)
		(layer "F.Cu")
		(net "DMI_CPU0_PCH_TX_C_DN<0>")
	)
	(segment
		(start 341.01278 -64.007238)
		(end 341.11184 -64.106298)
		(width 0.0889)
		(layer "F.Cu")
		(net "DMI_CPU0_PCH_TX_C_DN<0>")
	)
	(segment
		(start 341.11184 -62.247018)
		(end 341.01278 -62.346078)
		(width 0.0889)
		(layer "F.Cu")
		(net "DMI_CPU0_PCH_TX_C_DN<0>")
	)
	(segment
		(start 341.01278 -63.854838)
		(end 341.01278 -64.007238)
		(width 0.0889)
		(layer "F.Cu")
		(net "DMI_CPU0_PCH_TX_C_DN<0>")
	)
	(segment
		(start 340.783926 -60.891928)
		(end 340.783926 -61.081158)
		(width 0.0889)
		(layer "F.Cu")
		(net "DMI_CPU0_PCH_TX_C_DN<0>")
	)
	(segment
		(start 341.11184 -63.755778)
		(end 341.01278 -63.854838)
		(width 0.0889)
		(layer "F.Cu")
		(net "DMI_CPU0_PCH_TX_C_DN<0>")
	)
	(segment
		(start 340.78418 -60.541154)
		(end 340.88324 -60.640214)
		(width 0.0889)
		(layer "F.Cu")
		(net "DMI_CPU0_PCH_TX_C_DN<0>")
	)
	(segment
		(start 340.78418 -59.382914)
		(end 340.78418 -59.535314)
		(width 0.0889)
		(layer "F.Cu")
		(net "DMI_CPU0_PCH_TX_C_DN<0>")
	)
	(segment
		(start 341.11184 -61.744098)
		(end 341.01278 -61.843158)
		(width 0.0889)
		(layer "F.Cu")
		(net "DMI_CPU0_PCH_TX_C_DN<0>")
	)
	(segment
		(start 341.11184 -61.591698)
		(end 341.11184 -61.744098)
		(width 0.0889)
		(layer "F.Cu")
		(net "DMI_CPU0_PCH_TX_C_DN<0>")
	)
	(segment
		(start 341.01278 -63.504318)
		(end 341.11184 -63.603378)
		(width 0.0889)
		(layer "F.Cu")
		(net "DMI_CPU0_PCH_TX_C_DN<0>")
	)
	(segment
		(start 341.01278 -64.729868)
		(end 341.537036 -65.254124)
		(width 0.0889)
		(layer "F.Cu")
		(net "DMI_CPU0_PCH_TX_C_DN<0>")
	)
	(segment
		(start 341.570056 -65.750948)
		(end 341.570056 -66.698368)
		(width 0.13208)
		(layer "F.Cu")
		(net "DMI_CPU0_PCH_TX_C_DN<0>")
	)
	(segment
		(start 340.88324 -60.640214)
		(end 340.88324 -60.792614)
		(width 0.0889)
		(layer "F.Cu")
		(net "DMI_CPU0_PCH_TX_C_DN<0>")
	)
	(segment
		(start 341.01278 -64.357758)
		(end 341.01278 -64.729868)
		(width 0.0889)
		(layer "F.Cu")
		(net "DMI_CPU0_PCH_TX_C_DN<0>")
	)
	(segment
		(start 341.572596 -65.72885)
		(end 341.572596 -65.748408)
		(width 0.0889)
		(layer "F.Cu")
		(net "DMI_CPU0_PCH_TX_C_DN<0>")
	)
	(segment
		(start 342.113616 -69.445886)
		(end 342.43899 -69.77126)
		(width 0.13208)
		(layer "F.Cu")
		(net "DMI_CPU0_PCH_TX_C_DN<0>")
	)
	(segment
		(start 342.113616 -69.17436)
		(end 342.113616 -69.445886)
		(width 0.13208)
		(layer "F.Cu")
		(net "DMI_CPU0_PCH_TX_C_DN<0>")
	)
	(segment
		(start 341.01278 -61.995558)
		(end 341.11184 -62.094618)
		(width 0.0889)
		(layer "F.Cu")
		(net "DMI_CPU0_PCH_TX_C_DN<0>")
	)
	(segment
		(start 340.88324 -60.289694)
		(end 340.78418 -60.388754)
		(width 0.0889)
		(layer "F.Cu")
		(net "DMI_CPU0_PCH_TX_C_DN<0>")
	)
	(segment
		(start 341.01278 -62.498478)
		(end 341.11184 -62.597538)
		(width 0.0889)
		(layer "F.Cu")
		(net "DMI_CPU0_PCH_TX_C_DN<0>")
	)
	(segment
		(start 341.537036 -65.254124)
		(end 341.537036 -65.69329)
		(width 0.0889)
		(layer "F.Cu")
		(net "DMI_CPU0_PCH_TX_C_DN<0>")
	)
	(segment
		(start 341.11184 -62.597538)
		(end 341.11184 -62.749938)
		(width 0.0889)
		(layer "F.Cu")
		(net "DMI_CPU0_PCH_TX_C_DN<0>")
	)
	(segment
		(start 341.11184 -62.749938)
		(end 341.01278 -62.848998)
		(width 0.0889)
		(layer "F.Cu")
		(net "DMI_CPU0_PCH_TX_C_DN<0>")
	)
	(segment
		(start 341.01278 -63.351918)
		(end 341.01278 -63.504318)
		(width 0.0889)
		(layer "F.Cu")
		(net "DMI_CPU0_PCH_TX_C_DN<0>")
	)
	(segment
		(start 341.570056 -67.861434)
		(end 342.113616 -69.17436)
		(width 0.13208)
		(layer "F.Cu")
		(net "DMI_CPU0_PCH_TX_C_DN<0>")
	)
	(segment
		(start 340.78418 -60.388754)
		(end 340.78418 -60.541154)
		(width 0.0889)
		(layer "F.Cu")
		(net "DMI_CPU0_PCH_TX_C_DN<0>")
	)
	(segment
		(start 341.11184 -62.094618)
		(end 341.11184 -62.247018)
		(width 0.0889)
		(layer "F.Cu")
		(net "DMI_CPU0_PCH_TX_C_DN<0>")
	)
	(segment
		(start 341.11184 -63.603378)
		(end 341.11184 -63.755778)
		(width 0.0889)
		(layer "F.Cu")
		(net "DMI_CPU0_PCH_TX_C_DN<0>")
	)
	(segment
		(start 341.11184 -63.100458)
		(end 341.11184 -63.252858)
		(width 0.0889)
		(layer "F.Cu")
		(net "DMI_CPU0_PCH_TX_C_DN<0>")
	)
	(segment
		(start 341.537036 -65.69329)
		(end 341.572596 -65.72885)
		(width 0.0889)
		(layer "F.Cu")
		(net "DMI_CPU0_PCH_TX_C_DN<0>")
	)
	(segment
		(start 341.01278 -62.346078)
		(end 341.01278 -62.498478)
		(width 0.0889)
		(layer "F.Cu")
		(net "DMI_CPU0_PCH_TX_C_DN<0>")
	)
	(segment
		(start 341.11184 -64.106298)
		(end 341.11184 -64.258698)
		(width 0.0889)
		(layer "F.Cu")
		(net "DMI_CPU0_PCH_TX_C_DN<0>")
	)
	(segment
		(start 340.78418 -60.038234)
		(end 340.88324 -60.137294)
		(width 0.0889)
		(layer "F.Cu")
		(net "DMI_CPU0_PCH_TX_C_DN<0>")
	)
	(segment
		(start 341.01278 -63.001398)
		(end 341.11184 -63.100458)
		(width 0.0889)
		(layer "F.Cu")
		(net "DMI_CPU0_PCH_TX_C_DN<0>")
	)
	(segment
		(start 341.572596 -65.748408)
		(end 341.570056 -65.750948)
		(width 0.0889)
		(layer "F.Cu")
		(net "DMI_CPU0_PCH_TX_C_DN<0>")
	)
	(segment
		(start 341.01278 -61.310012)
		(end 341.01278 -61.492638)
		(width 0.0889)
		(layer "F.Cu")
		(net "DMI_CPU0_PCH_TX_C_DN<0>")
	)
	(segment
		(start 341.691976 -66.820288)
		(end 341.691976 -67.216528)
		(width 0.13208)
		(layer "F.Cu")
		(net "DMI_CPU0_PCH_TX_C_DN<0>")
	)
	(segment
		(start 341.01278 -61.492638)
		(end 341.11184 -61.591698)
		(width 0.0889)
		(layer "F.Cu")
		(net "DMI_CPU0_PCH_TX_C_DN<0>")
	)
	(segment
		(start 341.570056 -67.338448)
		(end 341.570056 -67.861434)
		(width 0.13208)
		(layer "F.Cu")
		(net "DMI_CPU0_PCH_TX_C_DN<0>")
	)
	(segment
		(start 340.88324 -59.786774)
		(end 340.78418 -59.885834)
		(width 0.0889)
		(layer "F.Cu")
		(net "DMI_CPU0_PCH_TX_C_DN<0>")
	)
	(segment
		(start 340.88324 -59.634374)
		(end 340.88324 -59.786774)
		(width 0.0889)
		(layer "F.Cu")
		(net "DMI_CPU0_PCH_TX_C_DN<0>")
	)
	(segment
		(start 340.88324 -60.792614)
		(end 340.783926 -60.891928)
		(width 0.0889)
		(layer "F.Cu")
		(net "DMI_CPU0_PCH_TX_C_DN<0>")
	)
	(segment
		(start 341.570056 -66.698368)
		(end 341.691976 -66.820288)
		(width 0.13208)
		(layer "F.Cu")
		(net "DMI_CPU0_PCH_TX_C_DN<0>")
	)
	(segment
		(start 344.63355 -55.968646)
		(end 344.364564 -55.498492)
		(width 0.13208)
		(layer "F.Cu")
		(net "DMI_CPU0_PCH_RX_DP<7>")
	)
	(via
		(at 344.364564 -55.498492)
		(size 0.4572)
		(drill 0.2032)
		(layers "F.Cu" "B.Cu")
		(net "DMI_CPU0_PCH_RX_DP<7>")
	)
	(segment
		(start 348.783656 -59.972702)
		(end 348.783656 -59.20232)
		(width 0.13208)
		(layer "B.Cu")
		(net "DMI_CPU0_PCH_RX_DP<7>")
	)
	(segment
		(start 349.409004 -64.18072)
		(end 349.081344 -64.50838)
		(width 0.13208)
		(layer "B.Cu")
		(net "DMI_CPU0_PCH_RX_DP<7>")
	)
	(segment
		(start 344.955876 -55.85968)
		(end 344.921586 -55.89397)
		(width 0.0889)
		(layer "B.Cu")
		(net "DMI_CPU0_PCH_RX_DP<7>")
	)
	(segment
		(start 348.983808 -64.50838)
		(end 348.89948 -64.424052)
		(width 0.13208)
		(layer "B.Cu")
		(net "DMI_CPU0_PCH_RX_DP<7>")
	)
	(segment
		(start 349.07728 -62.743588)
		(end 349.07728 -61.44895)
		(width 0.13208)
		(layer "B.Cu")
		(net "DMI_CPU0_PCH_RX_DP<7>")
	)
	(segment
		(start 348.89948 -64.424052)
		(end 348.89948 -63.172848)
		(width 0.13208)
		(layer "B.Cu")
		(net "DMI_CPU0_PCH_RX_DP<7>")
	)
	(segment
		(start 348.89948 -63.172848)
		(end 349.07728 -62.743588)
		(width 0.13208)
		(layer "B.Cu")
		(net "DMI_CPU0_PCH_RX_DP<7>")
	)
	(segment
		(start 344.921586 -55.89397)
		(end 344.453718 -55.89397)
		(width 0.0889)
		(layer "B.Cu")
		(net "DMI_CPU0_PCH_RX_DP<7>")
	)
	(segment
		(start 345.441016 -55.85968)
		(end 344.977974 -55.85968)
		(width 0.13208)
		(layer "B.Cu")
		(net "DMI_CPU0_PCH_RX_DP<7>")
	)
	(segment
		(start 349.081344 -64.50838)
		(end 348.983808 -64.50838)
		(width 0.13208)
		(layer "B.Cu")
		(net "DMI_CPU0_PCH_RX_DP<7>")
	)
	(segment
		(start 344.364564 -55.804816)
		(end 344.364564 -55.498492)
		(width 0.0889)
		(layer "B.Cu")
		(net "DMI_CPU0_PCH_RX_DP<7>")
	)
	(segment
		(start 344.977974 -55.85968)
		(end 344.955876 -55.85968)
		(width 0.0889)
		(layer "B.Cu")
		(net "DMI_CPU0_PCH_RX_DP<7>")
	)
	(segment
		(start 348.783656 -59.20232)
		(end 345.441016 -55.85968)
		(width 0.13208)
		(layer "B.Cu")
		(net "DMI_CPU0_PCH_RX_DP<7>")
	)
	(segment
		(start 344.453718 -55.89397)
		(end 344.364564 -55.804816)
		(width 0.0889)
		(layer "B.Cu")
		(net "DMI_CPU0_PCH_RX_DP<7>")
	)
	(segment
		(start 349.07728 -61.44895)
		(end 348.783656 -59.972702)
		(width 0.13208)
		(layer "B.Cu")
		(net "DMI_CPU0_PCH_RX_DP<7>")
	)
	(segment
		(start 343.81948 -55.498746)
		(end 343.550494 -55.028592)
		(width 0.13208)
		(layer "F.Cu")
		(net "DMI_CPU0_PCH_RX_DP<6>")
	)
	(via
		(at 343.550494 -55.028592)
		(size 0.4572)
		(drill 0.2032)
		(layers "F.Cu" "B.Cu")
		(net "DMI_CPU0_PCH_RX_DP<6>")
	)
	(segment
		(start 345.216988 -58.139076)
		(end 344.546682 -57.46877)
		(width 0.13208)
		(layer "B.Cu")
		(net "DMI_CPU0_PCH_RX_DP<6>")
	)
	(segment
		(start 345.473274 -58.245248)
		(end 345.216988 -58.139076)
		(width 0.13208)
		(layer "B.Cu")
		(net "DMI_CPU0_PCH_RX_DP<6>")
	)
	(segment
		(start 343.89949 -54.890924)
		(end 343.898728 -54.891178)
		(width 0.0889)
		(layer "B.Cu")
		(net "DMI_CPU0_PCH_RX_DP<6>")
	)
	(segment
		(start 343.87536 -55.780686)
		(end 343.86012 -55.754524)
		(width 0.0889)
		(layer "B.Cu")
		(net "DMI_CPU0_PCH_RX_DP<6>")
	)
	(segment
		(start 343.823798 -54.870858)
		(end 343.550494 -55.028592)
		(width 0.0889)
		(layer "B.Cu")
		(net "DMI_CPU0_PCH_RX_DP<6>")
	)
	(segment
		(start 344.531188 -57.453276)
		(end 344.531188 -57.404508)
		(width 0.0889)
		(layer "B.Cu")
		(net "DMI_CPU0_PCH_RX_DP<6>")
	)
	(segment
		(start 344.531188 -57.404508)
		(end 344.429842 -57.303162)
		(width 0.0889)
		(layer "B.Cu")
		(net "DMI_CPU0_PCH_RX_DP<6>")
	)
	(segment
		(start 345.605608 -58.841386)
		(end 345.605608 -58.377582)
		(width 0.13208)
		(layer "B.Cu")
		(net "DMI_CPU0_PCH_RX_DP<6>")
	)
	(segment
		(start 344.429842 -57.303162)
		(end 343.96426 -56.837834)
		(width 0.0889)
		(layer "B.Cu")
		(net "DMI_CPU0_PCH_RX_DP<6>")
	)
	(segment
		(start 344.546682 -57.46877)
		(end 344.531188 -57.453276)
		(width 0.0889)
		(layer "B.Cu")
		(net "DMI_CPU0_PCH_RX_DP<6>")
	)
	(segment
		(start 345.605608 -58.377582)
		(end 345.473274 -58.245248)
		(width 0.13208)
		(layer "B.Cu")
		(net "DMI_CPU0_PCH_RX_DP<6>")
	)
	(segment
		(start 343.898728 -54.891178)
		(end 343.823798 -54.870858)
		(width 0.0889)
		(layer "B.Cu")
		(net "DMI_CPU0_PCH_RX_DP<6>")
	)
	(segment
		(start 343.86012 -55.754524)
		(end 343.850722 -55.733696)
		(width 0.0889)
		(layer "B.Cu")
		(net "DMI_CPU0_PCH_RX_DP<6>")
	)
	(arc
		(start 343.87536 -56.156098)
		(mid 343.925689 -55.968392)
		(end 343.87536 -55.780686)
		(width 0.0889)
		(layer "B.Cu")
		(net "DMI_CPU0_PCH_RX_DP<6>")
	)
	(arc
		(start 343.875106 -56.720232)
		(mid 343.799711 -56.438119)
		(end 343.87536 -56.156098)
		(width 0.0889)
		(layer "B.Cu")
		(net "DMI_CPU0_PCH_RX_DP<6>")
	)
	(arc
		(start 343.87536 -55.216044)
		(mid 343.924541 -55.05625)
		(end 343.89949 -54.890924)
		(width 0.0889)
		(layer "B.Cu")
		(net "DMI_CPU0_PCH_RX_DP<6>")
	)
	(arc
		(start 343.850722 -55.733696)
		(mid 343.800194 -55.471879)
		(end 343.87536 -55.216044)
		(width 0.0889)
		(layer "B.Cu")
		(net "DMI_CPU0_PCH_RX_DP<6>")
	)
	(arc
		(start 343.96426 -56.837834)
		(mid 343.915842 -56.781946)
		(end 343.875106 -56.720232)
		(width 0.0889)
		(layer "B.Cu")
		(net "DMI_CPU0_PCH_RX_DP<6>")
	)
	(segment
		(start 342.735154 -55.498492)
		(end 343.006934 -55.968392)
		(width 0.13208)
		(layer "F.Cu")
		(net "DMI_CPU0_PCH_RX_DP<5>")
	)
	(segment
		(start 343.006934 -55.968392)
		(end 343.005156 -55.968646)
		(width 0.13208)
		(layer "F.Cu")
		(net "DMI_CPU0_PCH_RX_DP<5>")
	)
	(via
		(at 342.735154 -55.498492)
		(size 0.4572)
		(drill 0.2032)
		(layers "F.Cu" "B.Cu")
		(net "DMI_CPU0_PCH_RX_DP<5>")
	)
	(segment
		(start 345.027504 -60.507372)
		(end 345.250516 -60.730384)
		(width 0.13208)
		(layer "B.Cu")
		(net "DMI_CPU0_PCH_RX_DP<5>")
	)
	(segment
		(start 345.250516 -60.730384)
		(end 345.806776 -60.961016)
		(width 0.13208)
		(layer "B.Cu")
		(net "DMI_CPU0_PCH_RX_DP<5>")
	)
	(segment
		(start 342.735154 -55.498492)
		(end 343.008966 -55.656226)
		(width 0.0889)
		(layer "B.Cu")
		(net "DMI_CPU0_PCH_RX_DP<5>")
	)
	(segment
		(start 345.864434 -63.51143)
		(end 345.5543 -63.821564)
		(width 0.13208)
		(layer "B.Cu")
		(net "DMI_CPU0_PCH_RX_DP<5>")
	)
	(segment
		(start 343.653872 -57.824878)
		(end 343.669366 -57.840372)
		(width 0.0889)
		(layer "B.Cu")
		(net "DMI_CPU0_PCH_RX_DP<5>")
	)
	(segment
		(start 343.110566 -57.232804)
		(end 343.653872 -57.77611)
		(width 0.0889)
		(layer "B.Cu")
		(net "DMI_CPU0_PCH_RX_DP<5>")
	)
	(segment
		(start 343.008966 -55.656226)
		(end 343.031826 -55.74157)
		(width 0.0889)
		(layer "B.Cu")
		(net "DMI_CPU0_PCH_RX_DP<5>")
	)
	(segment
		(start 344.102182 -58.273188)
		(end 345.027504 -60.507372)
		(width 0.13208)
		(layer "B.Cu")
		(net "DMI_CPU0_PCH_RX_DP<5>")
	)
	(segment
		(start 345.806776 -60.961016)
		(end 345.996768 -61.151008)
		(width 0.13208)
		(layer "B.Cu")
		(net "DMI_CPU0_PCH_RX_DP<5>")
	)
	(segment
		(start 345.996768 -61.151008)
		(end 345.996768 -62.85738)
		(width 0.13208)
		(layer "B.Cu")
		(net "DMI_CPU0_PCH_RX_DP<5>")
	)
	(segment
		(start 343.669366 -57.840372)
		(end 344.102182 -58.273188)
		(width 0.13208)
		(layer "B.Cu")
		(net "DMI_CPU0_PCH_RX_DP<5>")
	)
	(segment
		(start 343.110566 -56.438292)
		(end 343.110566 -57.232804)
		(width 0.0889)
		(layer "B.Cu")
		(net "DMI_CPU0_PCH_RX_DP<5>")
	)
	(segment
		(start 343.653872 -57.77611)
		(end 343.653872 -57.824878)
		(width 0.0889)
		(layer "B.Cu")
		(net "DMI_CPU0_PCH_RX_DP<5>")
	)
	(segment
		(start 345.864434 -63.176912)
		(end 345.864434 -63.51143)
		(width 0.13208)
		(layer "B.Cu")
		(net "DMI_CPU0_PCH_RX_DP<5>")
	)
	(segment
		(start 345.996768 -62.85738)
		(end 345.864434 -63.176912)
		(width 0.13208)
		(layer "B.Cu")
		(net "DMI_CPU0_PCH_RX_DP<5>")
	)
	(arc
		(start 343.060274 -56.25084)
		(mid 343.097745 -56.34126)
		(end 343.110566 -56.438292)
		(width 0.0889)
		(layer "B.Cu")
		(net "DMI_CPU0_PCH_RX_DP<5>")
	)
	(arc
		(start 343.031826 -55.74157)
		(mid 343.027673 -55.751184)
		(end 343.023698 -55.760874)
		(width 0.0889)
		(layer "B.Cu")
		(net "DMI_CPU0_PCH_RX_DP<5>")
	)
	(arc
		(start 343.023698 -55.760874)
		(mid 342.986022 -56.01003)
		(end 343.060274 -56.25084)
		(width 0.0889)
		(layer "B.Cu")
		(net "DMI_CPU0_PCH_RX_DP<5>")
	)
	(segment
		(start 342.19134 -56.438546)
		(end 341.921338 -55.968646)
		(width 0.13208)
		(layer "F.Cu")
		(net "DMI_CPU0_PCH_RX_DP<4>")
	)
	(via
		(at 341.921338 -55.968646)
		(size 0.4572)
		(drill 0.2032)
		(layers "F.Cu" "B.Cu")
		(net "DMI_CPU0_PCH_RX_DP<4>")
	)
	(segment
		(start 343.485978 -60.486798)
		(end 343.647014 -60.553346)
		(width 0.13208)
		(layer "B.Cu")
		(net "DMI_CPU0_PCH_RX_DP<4>")
	)
	(segment
		(start 343.798652 -60.91936)
		(end 344.167968 -61.288676)
		(width 0.13208)
		(layer "B.Cu")
		(net "DMI_CPU0_PCH_RX_DP<4>")
	)
	(segment
		(start 342.170004 -57.545224)
		(end 342.170004 -57.818528)
		(width 0.0889)
		(layer "B.Cu")
		(net "DMI_CPU0_PCH_RX_DP<4>")
	)
	(segment
		(start 342.528144 -58.225436)
		(end 342.791796 -58.489088)
		(width 0.13208)
		(layer "B.Cu")
		(net "DMI_CPU0_PCH_RX_DP<4>")
	)
	(segment
		(start 343.003124 -58.999628)
		(end 342.936576 -59.160664)
		(width 0.13208)
		(layer "B.Cu")
		(net "DMI_CPU0_PCH_RX_DP<4>")
	)
	(segment
		(start 343.647014 -60.553346)
		(end 343.798652 -60.91936)
		(width 0.13208)
		(layer "B.Cu")
		(net "DMI_CPU0_PCH_RX_DP<4>")
	)
	(segment
		(start 342.070944 -57.268364)
		(end 342.070944 -57.446164)
		(width 0.0889)
		(layer "B.Cu")
		(net "DMI_CPU0_PCH_RX_DP<4>")
	)
	(segment
		(start 342.791796 -58.489088)
		(end 343.003124 -58.999628)
		(width 0.13208)
		(layer "B.Cu")
		(net "DMI_CPU0_PCH_RX_DP<4>")
	)
	(segment
		(start 342.51265 -58.161174)
		(end 342.51265 -58.209942)
		(width 0.0889)
		(layer "B.Cu")
		(net "DMI_CPU0_PCH_RX_DP<4>")
	)
	(segment
		(start 344.167968 -61.461904)
		(end 343.840308 -61.789564)
		(width 0.13208)
		(layer "B.Cu")
		(net "DMI_CPU0_PCH_RX_DP<4>")
	)
	(segment
		(start 342.170004 -56.437784)
		(end 342.170004 -56.615584)
		(width 0.0889)
		(layer "B.Cu")
		(net "DMI_CPU0_PCH_RX_DP<4>")
	)
	(segment
		(start 343.33434 -60.12053)
		(end 343.485978 -60.486798)
		(width 0.13208)
		(layer "B.Cu")
		(net "DMI_CPU0_PCH_RX_DP<4>")
	)
	(segment
		(start 344.167968 -61.288676)
		(end 344.167968 -61.461904)
		(width 0.13208)
		(layer "B.Cu")
		(net "DMI_CPU0_PCH_RX_DP<4>")
	)
	(segment
		(start 342.936576 -59.160664)
		(end 343.088214 -59.526932)
		(width 0.13208)
		(layer "B.Cu")
		(net "DMI_CPU0_PCH_RX_DP<4>")
	)
	(segment
		(start 342.51265 -58.209942)
		(end 342.528144 -58.225436)
		(width 0.0889)
		(layer "B.Cu")
		(net "DMI_CPU0_PCH_RX_DP<4>")
	)
	(segment
		(start 342.170004 -57.169304)
		(end 342.070944 -57.268364)
		(width 0.0889)
		(layer "B.Cu")
		(net "DMI_CPU0_PCH_RX_DP<4>")
	)
	(segment
		(start 342.070944 -57.446164)
		(end 342.170004 -57.545224)
		(width 0.0889)
		(layer "B.Cu")
		(net "DMI_CPU0_PCH_RX_DP<4>")
	)
	(segment
		(start 342.240616 -55.772558)
		(end 342.245696 -55.781448)
		(width 0.0889)
		(layer "B.Cu")
		(net "DMI_CPU0_PCH_RX_DP<4>")
	)
	(segment
		(start 342.170004 -57.818528)
		(end 342.51265 -58.161174)
		(width 0.0889)
		(layer "B.Cu")
		(net "DMI_CPU0_PCH_RX_DP<4>")
	)
	(segment
		(start 343.088214 -59.526932)
		(end 343.24925 -59.59348)
		(width 0.13208)
		(layer "B.Cu")
		(net "DMI_CPU0_PCH_RX_DP<4>")
	)
	(segment
		(start 343.400888 -59.959494)
		(end 343.33434 -60.12053)
		(width 0.13208)
		(layer "B.Cu")
		(net "DMI_CPU0_PCH_RX_DP<4>")
	)
	(segment
		(start 342.070944 -56.714644)
		(end 342.070944 -56.892444)
		(width 0.0889)
		(layer "B.Cu")
		(net "DMI_CPU0_PCH_RX_DP<4>")
	)
	(segment
		(start 342.170004 -56.991504)
		(end 342.170004 -57.169304)
		(width 0.0889)
		(layer "B.Cu")
		(net "DMI_CPU0_PCH_RX_DP<4>")
	)
	(segment
		(start 342.070944 -56.892444)
		(end 342.170004 -56.991504)
		(width 0.0889)
		(layer "B.Cu")
		(net "DMI_CPU0_PCH_RX_DP<4>")
	)
	(segment
		(start 341.921338 -55.655972)
		(end 341.978742 -55.598568)
		(width 0.0889)
		(layer "B.Cu")
		(net "DMI_CPU0_PCH_RX_DP<4>")
	)
	(segment
		(start 343.24925 -59.59348)
		(end 343.400888 -59.959494)
		(width 0.13208)
		(layer "B.Cu")
		(net "DMI_CPU0_PCH_RX_DP<4>")
	)
	(segment
		(start 341.921338 -55.968646)
		(end 341.921338 -55.655972)
		(width 0.0889)
		(layer "B.Cu")
		(net "DMI_CPU0_PCH_RX_DP<4>")
	)
	(segment
		(start 342.170004 -56.615584)
		(end 342.070944 -56.714644)
		(width 0.0889)
		(layer "B.Cu")
		(net "DMI_CPU0_PCH_RX_DP<4>")
	)
	(arc
		(start 342.245696 -55.781448)
		(mid 342.295839 -55.968646)
		(end 342.245696 -56.155844)
		(width 0.0889)
		(layer "B.Cu")
		(net "DMI_CPU0_PCH_RX_DP<4>")
	)
	(arc
		(start 342.245696 -56.155844)
		(mid 342.19425 -56.274233)
		(end 342.17102 -56.401208)
		(width 0.0889)
		(layer "B.Cu")
		(net "DMI_CPU0_PCH_RX_DP<4>")
	)
	(arc
		(start 341.978742 -55.598568)
		(mid 342.128855 -55.656724)
		(end 342.240616 -55.772558)
		(width 0.0889)
		(layer "B.Cu")
		(net "DMI_CPU0_PCH_RX_DP<4>")
	)
	(arc
		(start 342.17102 -56.401208)
		(mid 342.170214 -56.419488)
		(end 342.170004 -56.437784)
		(width 0.0889)
		(layer "B.Cu")
		(net "DMI_CPU0_PCH_RX_DP<4>")
	)
	(segment
		(start 341.105998 -54.558946)
		(end 341.214964 -54.747668)
		(width 0.13208)
		(layer "F.Cu")
		(net "DMI_CPU0_PCH_RX_DP<3>")
	)
	(segment
		(start 341.302848 -54.900068)
		(end 341.37727 -55.028846)
		(width 0.13208)
		(layer "F.Cu")
		(net "DMI_CPU0_PCH_RX_DP<3>")
	)
	(segment
		(start 341.214964 -54.747668)
		(end 341.302848 -54.900068)
		(width 0.13208)
		(layer "F.Cu")
		(net "DMI_CPU0_PCH_RX_DP<3>")
	)
	(via
		(at 341.105998 -54.558946)
		(size 0.4572)
		(drill 0.2032)
		(layers "F.Cu" "B.Cu")
		(net "DMI_CPU0_PCH_RX_DP<3>")
	)
	(segment
		(start 342.035638 -60.528962)
		(end 342.193626 -60.603384)
		(width 0.13208)
		(layer "B.Cu")
		(net "DMI_CPU0_PCH_RX_DP<3>")
	)
	(segment
		(start 341.370666 -56.858916)
		(end 341.370666 -57.902856)
		(width 0.0889)
		(layer "B.Cu")
		(net "DMI_CPU0_PCH_RX_DP<3>")
	)
	(segment
		(start 342.339168 -62.818772)
		(end 342.5698 -63.375794)
		(width 0.13208)
		(layer "B.Cu")
		(net "DMI_CPU0_PCH_RX_DP<3>")
	)
	(segment
		(start 341.79383 -59.16803)
		(end 341.79383 -59.190128)
		(width 0.0889)
		(layer "B.Cu")
		(net "DMI_CPU0_PCH_RX_DP<3>")
	)
	(segment
		(start 341.105998 -54.558946)
		(end 341.37981 -54.401212)
		(width 0.0889)
		(layer "B.Cu")
		(net "DMI_CPU0_PCH_RX_DP<3>")
	)
	(segment
		(start 342.5698 -63.503556)
		(end 342.251792 -63.821564)
		(width 0.13208)
		(layer "B.Cu")
		(net "DMI_CPU0_PCH_RX_DP<3>")
	)
	(segment
		(start 341.37981 -54.401212)
		(end 341.454994 -54.421532)
		(width 0.0889)
		(layer "B.Cu")
		(net "DMI_CPU0_PCH_RX_DP<3>")
	)
	(segment
		(start 341.79383 -59.190128)
		(end 341.79383 -59.487308)
		(width 0.13208)
		(layer "B.Cu")
		(net "DMI_CPU0_PCH_RX_DP<3>")
	)
	(segment
		(start 341.432642 -56.623966)
		(end 341.432388 -56.624474)
		(width 0.0889)
		(layer "B.Cu")
		(net "DMI_CPU0_PCH_RX_DP<3>")
	)
	(segment
		(start 341.455502 -54.421278)
		(end 341.455756 -54.421532)
		(width 0.0889)
		(layer "B.Cu")
		(net "DMI_CPU0_PCH_RX_DP<3>")
	)
	(segment
		(start 341.454994 -54.421532)
		(end 341.455502 -54.421278)
		(width 0.0889)
		(layer "B.Cu")
		(net "DMI_CPU0_PCH_RX_DP<3>")
	)
	(segment
		(start 341.828374 -58.818018)
		(end 341.828374 -59.133486)
		(width 0.0889)
		(layer "B.Cu")
		(net "DMI_CPU0_PCH_RX_DP<3>")
	)
	(segment
		(start 341.97671 -59.998102)
		(end 341.902288 -60.155836)
		(width 0.13208)
		(layer "B.Cu")
		(net "DMI_CPU0_PCH_RX_DP<3>")
	)
	(segment
		(start 342.5698 -63.375794)
		(end 342.5698 -63.503556)
		(width 0.13208)
		(layer "B.Cu")
		(net "DMI_CPU0_PCH_RX_DP<3>")
	)
	(segment
		(start 342.193626 -60.603384)
		(end 342.339168 -61.010546)
		(width 0.13208)
		(layer "B.Cu")
		(net "DMI_CPU0_PCH_RX_DP<3>")
	)
	(segment
		(start 341.902288 -60.155836)
		(end 342.035638 -60.528962)
		(width 0.13208)
		(layer "B.Cu")
		(net "DMI_CPU0_PCH_RX_DP<3>")
	)
	(segment
		(start 341.79383 -59.487308)
		(end 341.97671 -59.998102)
		(width 0.13208)
		(layer "B.Cu")
		(net "DMI_CPU0_PCH_RX_DP<3>")
	)
	(segment
		(start 342.339168 -61.010546)
		(end 342.339168 -62.818772)
		(width 0.13208)
		(layer "B.Cu")
		(net "DMI_CPU0_PCH_RX_DP<3>")
	)
	(segment
		(start 341.828374 -59.133486)
		(end 341.79383 -59.16803)
		(width 0.0889)
		(layer "B.Cu")
		(net "DMI_CPU0_PCH_RX_DP<3>")
	)
	(segment
		(start 341.370666 -57.902856)
		(end 341.828374 -58.818018)
		(width 0.0889)
		(layer "B.Cu")
		(net "DMI_CPU0_PCH_RX_DP<3>")
	)
	(arc
		(start 341.431372 -56.25084)
		(mid 341.481631 -56.437239)
		(end 341.432642 -56.623966)
		(width 0.0889)
		(layer "B.Cu")
		(net "DMI_CPU0_PCH_RX_DP<3>")
	)
	(arc
		(start 341.455756 -54.421532)
		(mid 341.480665 -54.586863)
		(end 341.431372 -54.746652)
		(width 0.0889)
		(layer "B.Cu")
		(net "DMI_CPU0_PCH_RX_DP<3>")
	)
	(arc
		(start 341.431372 -54.746652)
		(mid 341.355918 -55.028846)
		(end 341.431372 -55.31104)
		(width 0.0889)
		(layer "B.Cu")
		(net "DMI_CPU0_PCH_RX_DP<3>")
	)
	(arc
		(start 341.431372 -55.31104)
		(mid 341.481633 -55.498746)
		(end 341.431372 -55.686452)
		(width 0.0889)
		(layer "B.Cu")
		(net "DMI_CPU0_PCH_RX_DP<3>")
	)
	(arc
		(start 341.432388 -56.624474)
		(mid 341.386319 -56.737689)
		(end 341.370666 -56.858916)
		(width 0.0889)
		(layer "B.Cu")
		(net "DMI_CPU0_PCH_RX_DP<3>")
	)
	(arc
		(start 341.431372 -55.686452)
		(mid 341.355918 -55.968646)
		(end 341.431372 -56.25084)
		(width 0.0889)
		(layer "B.Cu")
		(net "DMI_CPU0_PCH_RX_DP<3>")
	)
	(segment
		(start 341.37727 -55.968646)
		(end 341.105998 -55.498746)
		(width 0.13208)
		(layer "F.Cu")
		(net "DMI_CPU0_PCH_RX_DP<2>")
	)
	(via
		(at 341.105998 -55.498746)
		(size 0.4572)
		(drill 0.2032)
		(layers "F.Cu" "B.Cu")
		(net "DMI_CPU0_PCH_RX_DP<2>")
	)
	(segment
		(start 341.00008 -61.469016)
		(end 341.320628 -61.789564)
		(width 0.13208)
		(layer "B.Cu")
		(net "DMI_CPU0_PCH_RX_DP<2>")
	)
	(segment
		(start 340.877906 -60.949332)
		(end 341.00008 -61.071506)
		(width 0.13208)
		(layer "B.Cu")
		(net "DMI_CPU0_PCH_RX_DP<2>")
	)
	(segment
		(start 341.001096 -60.558426)
		(end 340.877906 -60.681616)
		(width 0.13208)
		(layer "B.Cu")
		(net "DMI_CPU0_PCH_RX_DP<2>")
	)
	(segment
		(start 340.877906 -59.270646)
		(end 340.877906 -60.038996)
		(width 0.13208)
		(layer "B.Cu")
		(net "DMI_CPU0_PCH_RX_DP<2>")
	)
	(segment
		(start 340.832186 -55.341012)
		(end 340.757002 -55.361332)
		(width 0.0889)
		(layer "B.Cu")
		(net "DMI_CPU0_PCH_RX_DP<2>")
	)
	(segment
		(start 340.843616 -59.214258)
		(end 340.877906 -59.248548)
		(width 0.0889)
		(layer "B.Cu")
		(net "DMI_CPU0_PCH_RX_DP<2>")
	)
	(segment
		(start 341.105998 -55.498746)
		(end 340.832186 -55.341012)
		(width 0.0889)
		(layer "B.Cu")
		(net "DMI_CPU0_PCH_RX_DP<2>")
	)
	(segment
		(start 340.877906 -59.248548)
		(end 340.877906 -59.270646)
		(width 0.0889)
		(layer "B.Cu")
		(net "DMI_CPU0_PCH_RX_DP<2>")
	)
	(segment
		(start 340.843616 -56.829452)
		(end 340.843616 -59.214258)
		(width 0.0889)
		(layer "B.Cu")
		(net "DMI_CPU0_PCH_RX_DP<2>")
	)
	(segment
		(start 341.00008 -61.071506)
		(end 341.00008 -61.469016)
		(width 0.13208)
		(layer "B.Cu")
		(net "DMI_CPU0_PCH_RX_DP<2>")
	)
	(segment
		(start 340.877906 -60.038996)
		(end 341.001096 -60.162186)
		(width 0.13208)
		(layer "B.Cu")
		(net "DMI_CPU0_PCH_RX_DP<2>")
	)
	(segment
		(start 340.877906 -60.681616)
		(end 340.877906 -60.949332)
		(width 0.13208)
		(layer "B.Cu")
		(net "DMI_CPU0_PCH_RX_DP<2>")
	)
	(segment
		(start 341.001096 -60.162186)
		(end 341.001096 -60.558426)
		(width 0.13208)
		(layer "B.Cu")
		(net "DMI_CPU0_PCH_RX_DP<2>")
	)
	(arc
		(start 340.780878 -56.625744)
		(mid 340.806533 -56.675777)
		(end 340.827106 -56.728106)
		(width 0.0889)
		(layer "B.Cu")
		(net "DMI_CPU0_PCH_RX_DP<2>")
	)
	(arc
		(start 340.827106 -56.728106)
		(mid 340.839433 -56.778114)
		(end 340.843616 -56.829452)
		(width 0.0889)
		(layer "B.Cu")
		(net "DMI_CPU0_PCH_RX_DP<2>")
	)
	(arc
		(start 340.757002 -55.361332)
		(mid 340.731941 -55.526349)
		(end 340.780878 -55.685944)
		(width 0.0889)
		(layer "B.Cu")
		(net "DMI_CPU0_PCH_RX_DP<2>")
	)
	(arc
		(start 340.780878 -56.251348)
		(mid 340.730837 -56.438546)
		(end 340.780878 -56.625744)
		(width 0.0889)
		(layer "B.Cu")
		(net "DMI_CPU0_PCH_RX_DP<2>")
	)
	(arc
		(start 340.780878 -55.685944)
		(mid 340.856552 -55.968646)
		(end 340.780878 -56.251348)
		(width 0.0889)
		(layer "B.Cu")
		(net "DMI_CPU0_PCH_RX_DP<2>")
	)
	(segment
		(start 339.749638 -56.908446)
		(end 339.748876 -56.908446)
		(width 0.13208)
		(layer "F.Cu")
		(net "DMI_CPU0_PCH_RX_DP<1>")
	)
	(segment
		(start 339.477858 -56.438546)
		(end 339.749638 -56.908446)
		(width 0.13208)
		(layer "F.Cu")
		(net "DMI_CPU0_PCH_RX_DP<1>")
	)
	(via
		(at 339.477858 -56.438546)
		(size 0.4572)
		(drill 0.2032)
		(layers "F.Cu" "B.Cu")
		(net "DMI_CPU0_PCH_RX_DP<1>")
	)
	(segment
		(start 339.66658 -58.633868)
		(end 339.701124 -58.599324)
		(width 0.0889)
		(layer "B.Cu")
		(net "DMI_CPU0_PCH_RX_DP<1>")
	)
	(segment
		(start 339.701124 -57.521856)
		(end 339.701124 -56.969914)
		(width 0.0889)
		(layer "B.Cu")
		(net "DMI_CPU0_PCH_RX_DP<1>")
	)
	(segment
		(start 339.701124 -56.969914)
		(end 339.70087 -56.96966)
		(width 0.0889)
		(layer "B.Cu")
		(net "DMI_CPU0_PCH_RX_DP<1>")
	)
	(segment
		(start 338.972398 -60.443872)
		(end 339.22589 -60.190634)
		(width 0.13208)
		(layer "B.Cu")
		(net "DMI_CPU0_PCH_RX_DP<1>")
	)
	(segment
		(start 339.602064 -57.885076)
		(end 339.602064 -57.620916)
		(width 0.0889)
		(layer "B.Cu")
		(net "DMI_CPU0_PCH_RX_DP<1>")
	)
	(segment
		(start 339.904324 -56.766206)
		(end 339.904324 -56.448706)
		(width 0.0889)
		(layer "B.Cu")
		(net "DMI_CPU0_PCH_RX_DP<1>")
	)
	(segment
		(start 339.828632 -56.335168)
		(end 339.70595 -56.30672)
		(width 0.0889)
		(layer "B.Cu")
		(net "DMI_CPU0_PCH_RX_DP<1>")
	)
	(segment
		(start 339.74532 -65.856104)
		(end 339.74532 -64.434466)
		(width 0.13208)
		(layer "B.Cu")
		(net "DMI_CPU0_PCH_RX_DP<1>")
	)
	(segment
		(start 339.70595 -56.30672)
		(end 339.477858 -56.438546)
		(width 0.0889)
		(layer "B.Cu")
		(net "DMI_CPU0_PCH_RX_DP<1>")
	)
	(segment
		(start 339.66658 -58.655966)
		(end 339.66658 -58.633868)
		(width 0.0889)
		(layer "B.Cu")
		(net "DMI_CPU0_PCH_RX_DP<1>")
	)
	(segment
		(start 339.701124 -58.599324)
		(end 339.701124 -57.984136)
		(width 0.0889)
		(layer "B.Cu")
		(net "DMI_CPU0_PCH_RX_DP<1>")
	)
	(segment
		(start 338.681568 -61.866526)
		(end 338.681568 -61.14542)
		(width 0.13208)
		(layer "B.Cu")
		(net "DMI_CPU0_PCH_RX_DP<1>")
	)
	(segment
		(start 339.352636 -59.884818)
		(end 339.352636 -59.71794)
		(width 0.13208)
		(layer "B.Cu")
		(net "DMI_CPU0_PCH_RX_DP<1>")
	)
	(segment
		(start 339.352636 -59.71794)
		(end 339.66658 -58.683144)
		(width 0.13208)
		(layer "B.Cu")
		(net "DMI_CPU0_PCH_RX_DP<1>")
	)
	(segment
		(start 339.22589 -60.190634)
		(end 339.352636 -59.884818)
		(width 0.13208)
		(layer "B.Cu")
		(net "DMI_CPU0_PCH_RX_DP<1>")
	)
	(segment
		(start 338.681568 -61.14542)
		(end 338.972398 -60.443872)
		(width 0.13208)
		(layer "B.Cu")
		(net "DMI_CPU0_PCH_RX_DP<1>")
	)
	(segment
		(start 339.904324 -56.448706)
		(end 339.828632 -56.335168)
		(width 0.0889)
		(layer "B.Cu")
		(net "DMI_CPU0_PCH_RX_DP<1>")
	)
	(segment
		(start 339.74532 -64.434466)
		(end 338.681568 -61.866526)
		(width 0.13208)
		(layer "B.Cu")
		(net "DMI_CPU0_PCH_RX_DP<1>")
	)
	(segment
		(start 339.70087 -56.96966)
		(end 339.904324 -56.766206)
		(width 0.0889)
		(layer "B.Cu")
		(net "DMI_CPU0_PCH_RX_DP<1>")
	)
	(segment
		(start 339.602064 -57.620916)
		(end 339.701124 -57.521856)
		(width 0.0889)
		(layer "B.Cu")
		(net "DMI_CPU0_PCH_RX_DP<1>")
	)
	(segment
		(start 339.44306 -66.158364)
		(end 339.74532 -65.856104)
		(width 0.13208)
		(layer "B.Cu")
		(net "DMI_CPU0_PCH_RX_DP<1>")
	)
	(segment
		(start 339.66658 -58.683144)
		(end 339.66658 -58.655966)
		(width 0.13208)
		(layer "B.Cu")
		(net "DMI_CPU0_PCH_RX_DP<1>")
	)
	(segment
		(start 339.701124 -57.984136)
		(end 339.602064 -57.885076)
		(width 0.0889)
		(layer "B.Cu")
		(net "DMI_CPU0_PCH_RX_DP<1>")
	)
	(segment
		(start 339.477858 -55.498746)
		(end 339.749638 -55.968646)
		(width 0.13208)
		(layer "F.Cu")
		(net "DMI_CPU0_PCH_RX_DP<0>")
	)
	(segment
		(start 339.749638 -55.968646)
		(end 339.748876 -55.968646)
		(width 0.13208)
		(layer "F.Cu")
		(net "DMI_CPU0_PCH_RX_DP<0>")
	)
	(via
		(at 339.477858 -55.498746)
		(size 0.4572)
		(drill 0.2032)
		(layers "F.Cu" "B.Cu")
		(net "DMI_CPU0_PCH_RX_DP<0>")
	)
	(segment
		(start 338.215986 -59.006486)
		(end 338.40293 -58.819288)
		(width 0.0889)
		(layer "B.Cu")
		(net "DMI_CPU0_PCH_RX_DP<0>")
	)
	(segment
		(start 337.44535 -62.474094)
		(end 337.44535 -61.538104)
		(width 0.13208)
		(layer "B.Cu")
		(net "DMI_CPU0_PCH_RX_DP<0>")
	)
	(segment
		(start 337.44535 -61.516006)
		(end 337.41106 -61.481716)
		(width 0.0889)
		(layer "B.Cu")
		(net "DMI_CPU0_PCH_RX_DP<0>")
	)
	(segment
		(start 337.764882 -60.021216)
		(end 337.764882 -59.317128)
		(width 0.0889)
		(layer "B.Cu")
		(net "DMI_CPU0_PCH_RX_DP<0>")
	)
	(segment
		(start 339.103462 -57.978802)
		(end 339.103462 -55.28437)
		(width 0.0889)
		(layer "B.Cu")
		(net "DMI_CPU0_PCH_RX_DP<0>")
	)
	(segment
		(start 338.40293 -58.679334)
		(end 338.58962 -58.492644)
		(width 0.0889)
		(layer "B.Cu")
		(net "DMI_CPU0_PCH_RX_DP<0>")
	)
	(segment
		(start 337.44535 -61.538104)
		(end 337.44535 -61.516006)
		(width 0.0889)
		(layer "B.Cu")
		(net "DMI_CPU0_PCH_RX_DP<0>")
	)
	(segment
		(start 338.916772 -58.305446)
		(end 338.916772 -58.165492)
		(width 0.0889)
		(layer "B.Cu")
		(net "DMI_CPU0_PCH_RX_DP<0>")
	)
	(segment
		(start 339.103208 -55.284116)
		(end 339.263228 -55.124096)
		(width 0.0889)
		(layer "B.Cu")
		(net "DMI_CPU0_PCH_RX_DP<0>")
	)
	(segment
		(start 337.863942 -60.384436)
		(end 337.863942 -60.120276)
		(width 0.0889)
		(layer "B.Cu")
		(net "DMI_CPU0_PCH_RX_DP<0>")
	)
	(segment
		(start 339.263228 -55.124096)
		(end 339.388958 -55.124096)
		(width 0.0889)
		(layer "B.Cu")
		(net "DMI_CPU0_PCH_RX_DP<0>")
	)
	(segment
		(start 337.764628 -60.48375)
		(end 337.863942 -60.384436)
		(width 0.0889)
		(layer "B.Cu")
		(net "DMI_CPU0_PCH_RX_DP<0>")
	)
	(segment
		(start 337.41106 -61.481716)
		(end 337.41106 -61.009784)
		(width 0.0889)
		(layer "B.Cu")
		(net "DMI_CPU0_PCH_RX_DP<0>")
	)
	(segment
		(start 337.805522 -63.721488)
		(end 337.805522 -63.344298)
		(width 0.13208)
		(layer "B.Cu")
		(net "DMI_CPU0_PCH_RX_DP<0>")
	)
	(segment
		(start 338.40293 -58.819288)
		(end 338.40293 -58.679334)
		(width 0.0889)
		(layer "B.Cu")
		(net "DMI_CPU0_PCH_RX_DP<0>")
	)
	(segment
		(start 339.477858 -55.212996)
		(end 339.477858 -55.498746)
		(width 0.0889)
		(layer "B.Cu")
		(net "DMI_CPU0_PCH_RX_DP<0>")
	)
	(segment
		(start 339.103462 -55.28437)
		(end 339.103208 -55.284116)
		(width 0.0889)
		(layer "B.Cu")
		(net "DMI_CPU0_PCH_RX_DP<0>")
	)
	(segment
		(start 338.58962 -58.492644)
		(end 338.729828 -58.492644)
		(width 0.0889)
		(layer "B.Cu")
		(net "DMI_CPU0_PCH_RX_DP<0>")
	)
	(segment
		(start 337.41106 -61.009784)
		(end 337.764628 -60.656216)
		(width 0.0889)
		(layer "B.Cu")
		(net "DMI_CPU0_PCH_RX_DP<0>")
	)
	(segment
		(start 338.729828 -58.492644)
		(end 338.916772 -58.305446)
		(width 0.0889)
		(layer "B.Cu")
		(net "DMI_CPU0_PCH_RX_DP<0>")
	)
	(segment
		(start 337.805522 -63.344298)
		(end 337.44535 -62.474094)
		(width 0.13208)
		(layer "B.Cu")
		(net "DMI_CPU0_PCH_RX_DP<0>")
	)
	(segment
		(start 338.133182 -64.049148)
		(end 337.805522 -63.721488)
		(width 0.13208)
		(layer "B.Cu")
		(net "DMI_CPU0_PCH_RX_DP<0>")
	)
	(segment
		(start 338.075524 -59.006486)
		(end 338.215986 -59.006486)
		(width 0.0889)
		(layer "B.Cu")
		(net "DMI_CPU0_PCH_RX_DP<0>")
	)
	(segment
		(start 337.764882 -59.317128)
		(end 338.075524 -59.006486)
		(width 0.0889)
		(layer "B.Cu")
		(net "DMI_CPU0_PCH_RX_DP<0>")
	)
	(segment
		(start 338.916772 -58.165492)
		(end 339.103462 -57.978802)
		(width 0.0889)
		(layer "B.Cu")
		(net "DMI_CPU0_PCH_RX_DP<0>")
	)
	(segment
		(start 339.388958 -55.124096)
		(end 339.477858 -55.212996)
		(width 0.0889)
		(layer "B.Cu")
		(net "DMI_CPU0_PCH_RX_DP<0>")
	)
	(segment
		(start 337.863942 -60.120276)
		(end 337.764882 -60.021216)
		(width 0.0889)
		(layer "B.Cu")
		(net "DMI_CPU0_PCH_RX_DP<0>")
	)
	(segment
		(start 337.764628 -60.656216)
		(end 337.764628 -60.48375)
		(width 0.0889)
		(layer "B.Cu")
		(net "DMI_CPU0_PCH_RX_DP<0>")
	)
	(segment
		(start 344.63355 -56.908446)
		(end 344.364564 -56.438292)
		(width 0.13208)
		(layer "F.Cu")
		(net "DMI_CPU0_PCH_RX_DN<7>")
	)
	(via
		(at 344.364564 -56.438292)
		(size 0.4572)
		(drill 0.2032)
		(layers "F.Cu" "B.Cu")
		(net "DMI_CPU0_PCH_RX_DN<7>")
	)
	(segment
		(start 344.921332 -56.084216)
		(end 344.453464 -56.084216)
		(width 0.0889)
		(layer "B.Cu")
		(net "DMI_CPU0_PCH_RX_DN<7>")
	)
	(segment
		(start 348.524576 -59.998356)
		(end 348.524576 -59.309762)
		(width 0.13208)
		(layer "B.Cu")
		(net "DMI_CPU0_PCH_RX_DN<7>")
	)
	(segment
		(start 348.6404 -64.531494)
		(end 348.6404 -63.121286)
		(width 0.13208)
		(layer "B.Cu")
		(net "DMI_CPU0_PCH_RX_DN<7>")
	)
	(segment
		(start 344.364564 -56.173116)
		(end 344.364564 -56.438292)
		(width 0.0889)
		(layer "B.Cu")
		(net "DMI_CPU0_PCH_RX_DN<7>")
	)
	(segment
		(start 345.333574 -56.11876)
		(end 344.977974 -56.11876)
		(width 0.13208)
		(layer "B.Cu")
		(net "DMI_CPU0_PCH_RX_DN<7>")
	)
	(segment
		(start 348.876366 -64.76746)
		(end 348.6404 -64.531494)
		(width 0.13208)
		(layer "B.Cu")
		(net "DMI_CPU0_PCH_RX_DN<7>")
	)
	(segment
		(start 349.409004 -65.09512)
		(end 349.081344 -64.76746)
		(width 0.13208)
		(layer "B.Cu")
		(net "DMI_CPU0_PCH_RX_DN<7>")
	)
	(segment
		(start 348.8182 -62.692026)
		(end 348.8182 -61.474604)
		(width 0.13208)
		(layer "B.Cu")
		(net "DMI_CPU0_PCH_RX_DN<7>")
	)
	(segment
		(start 344.977974 -56.11876)
		(end 344.955876 -56.11876)
		(width 0.0889)
		(layer "B.Cu")
		(net "DMI_CPU0_PCH_RX_DN<7>")
	)
	(segment
		(start 348.8182 -61.474604)
		(end 348.524576 -59.998356)
		(width 0.13208)
		(layer "B.Cu")
		(net "DMI_CPU0_PCH_RX_DN<7>")
	)
	(segment
		(start 344.453464 -56.084216)
		(end 344.364564 -56.173116)
		(width 0.0889)
		(layer "B.Cu")
		(net "DMI_CPU0_PCH_RX_DN<7>")
	)
	(segment
		(start 349.081344 -64.76746)
		(end 348.876366 -64.76746)
		(width 0.13208)
		(layer "B.Cu")
		(net "DMI_CPU0_PCH_RX_DN<7>")
	)
	(segment
		(start 344.955876 -56.11876)
		(end 344.921332 -56.084216)
		(width 0.0889)
		(layer "B.Cu")
		(net "DMI_CPU0_PCH_RX_DN<7>")
	)
	(segment
		(start 348.524576 -59.309762)
		(end 345.333574 -56.11876)
		(width 0.13208)
		(layer "B.Cu")
		(net "DMI_CPU0_PCH_RX_DN<7>")
	)
	(segment
		(start 348.6404 -63.121286)
		(end 348.8182 -62.692026)
		(width 0.13208)
		(layer "B.Cu")
		(net "DMI_CPU0_PCH_RX_DN<7>")
	)
	(segment
		(start 344.364564 -54.558692)
		(end 344.472768 -54.747668)
		(width 0.13208)
		(layer "F.Cu")
		(net "DMI_CPU0_PCH_RX_DN<6>")
	)
	(segment
		(start 344.472768 -54.747668)
		(end 344.63355 -55.028846)
		(width 0.13208)
		(layer "F.Cu")
		(net "DMI_CPU0_PCH_RX_DN<6>")
	)
	(via
		(at 344.364564 -54.558692)
		(size 0.4572)
		(drill 0.2032)
		(layers "F.Cu" "B.Cu")
		(net "DMI_CPU0_PCH_RX_DN<6>")
	)
	(segment
		(start 345.364308 -57.91962)
		(end 344.73007 -57.285382)
		(width 0.13208)
		(layer "B.Cu")
		(net "DMI_CPU0_PCH_RX_DN<6>")
	)
	(segment
		(start 346.252292 -58.194702)
		(end 345.78925 -58.194702)
		(width 0.13208)
		(layer "B.Cu")
		(net "DMI_CPU0_PCH_RX_DN<6>")
	)
	(segment
		(start 344.040206 -55.68569)
		(end 344.029538 -55.667148)
		(width 0.0889)
		(layer "B.Cu")
		(net "DMI_CPU0_PCH_RX_DN<6>")
	)
	(segment
		(start 344.029538 -55.667148)
		(end 344.023696 -55.654448)
		(width 0.0889)
		(layer "B.Cu")
		(net "DMI_CPU0_PCH_RX_DN<6>")
	)
	(segment
		(start 345.620086 -58.025538)
		(end 345.364308 -57.91962)
		(width 0.13208)
		(layer "B.Cu")
		(net "DMI_CPU0_PCH_RX_DN<6>")
	)
	(segment
		(start 344.714576 -57.269888)
		(end 344.665808 -57.269888)
		(width 0.0889)
		(layer "B.Cu")
		(net "DMI_CPU0_PCH_RX_DN<6>")
	)
	(segment
		(start 344.068654 -54.801516)
		(end 344.09126 -54.716426)
		(width 0.0889)
		(layer "B.Cu")
		(net "DMI_CPU0_PCH_RX_DN<6>")
	)
	(segment
		(start 344.665808 -57.269888)
		(end 344.099388 -56.703468)
		(width 0.0889)
		(layer "B.Cu")
		(net "DMI_CPU0_PCH_RX_DN<6>")
	)
	(segment
		(start 345.78925 -58.194702)
		(end 345.620086 -58.025538)
		(width 0.13208)
		(layer "B.Cu")
		(net "DMI_CPU0_PCH_RX_DN<6>")
	)
	(segment
		(start 344.09126 -54.716426)
		(end 344.364564 -54.558692)
		(width 0.0889)
		(layer "B.Cu")
		(net "DMI_CPU0_PCH_RX_DN<6>")
	)
	(segment
		(start 344.73007 -57.285382)
		(end 344.714576 -57.269888)
		(width 0.0889)
		(layer "B.Cu")
		(net "DMI_CPU0_PCH_RX_DN<6>")
	)
	(arc
		(start 344.040206 -56.251094)
		(mid 344.115948 -55.968392)
		(end 344.040206 -55.68569)
		(width 0.0889)
		(layer "B.Cu")
		(net "DMI_CPU0_PCH_RX_DN<6>")
	)
	(arc
		(start 344.040206 -56.62549)
		(mid 343.990063 -56.438292)
		(end 344.040206 -56.251094)
		(width 0.0889)
		(layer "B.Cu")
		(net "DMI_CPU0_PCH_RX_DN<6>")
	)
	(arc
		(start 344.023696 -55.654448)
		(mid 343.990246 -55.48085)
		(end 344.040206 -55.311294)
		(width 0.0889)
		(layer "B.Cu")
		(net "DMI_CPU0_PCH_RX_DN<6>")
	)
	(arc
		(start 344.099388 -56.703468)
		(mid 344.067242 -56.666418)
		(end 344.040206 -56.62549)
		(width 0.0889)
		(layer "B.Cu")
		(net "DMI_CPU0_PCH_RX_DN<6>")
	)
	(arc
		(start 344.040206 -55.311294)
		(mid 344.115199 -55.059802)
		(end 344.068654 -54.801516)
		(width 0.0889)
		(layer "B.Cu")
		(net "DMI_CPU0_PCH_RX_DN<6>")
	)
	(segment
		(start 343.81948 -56.438546)
		(end 343.550494 -55.968392)
		(width 0.13208)
		(layer "F.Cu")
		(net "DMI_CPU0_PCH_RX_DN<5>")
	)
	(via
		(at 343.550494 -55.968392)
		(size 0.4572)
		(drill 0.2032)
		(layers "F.Cu" "B.Cu")
		(net "DMI_CPU0_PCH_RX_DN<5>")
	)
	(segment
		(start 344.321638 -58.125868)
		(end 345.247214 -60.36056)
		(width 0.13208)
		(layer "B.Cu")
		(net "DMI_CPU0_PCH_RX_DN<5>")
	)
	(segment
		(start 343.83726 -57.64149)
		(end 343.852754 -57.656984)
		(width 0.0889)
		(layer "B.Cu")
		(net "DMI_CPU0_PCH_RX_DN<5>")
	)
	(segment
		(start 345.247214 -60.36056)
		(end 345.397328 -60.510674)
		(width 0.13208)
		(layer "B.Cu")
		(net "DMI_CPU0_PCH_RX_DN<5>")
	)
	(segment
		(start 343.301066 -57.154064)
		(end 343.788492 -57.64149)
		(width 0.0889)
		(layer "B.Cu")
		(net "DMI_CPU0_PCH_RX_DN<5>")
	)
	(segment
		(start 346.123514 -63.482982)
		(end 346.462096 -63.821564)
		(width 0.13208)
		(layer "B.Cu")
		(net "DMI_CPU0_PCH_RX_DN<5>")
	)
	(segment
		(start 343.788492 -57.64149)
		(end 343.83726 -57.64149)
		(width 0.0889)
		(layer "B.Cu")
		(net "DMI_CPU0_PCH_RX_DN<5>")
	)
	(segment
		(start 346.123514 -63.228474)
		(end 346.123514 -63.482982)
		(width 0.13208)
		(layer "B.Cu")
		(net "DMI_CPU0_PCH_RX_DN<5>")
	)
	(segment
		(start 346.255848 -62.908942)
		(end 346.123514 -63.228474)
		(width 0.13208)
		(layer "B.Cu")
		(net "DMI_CPU0_PCH_RX_DN<5>")
	)
	(segment
		(start 343.301066 -56.438038)
		(end 343.301066 -57.154064)
		(width 0.0889)
		(layer "B.Cu")
		(net "DMI_CPU0_PCH_RX_DN<5>")
	)
	(segment
		(start 346.255848 -61.043566)
		(end 346.255848 -62.908942)
		(width 0.13208)
		(layer "B.Cu")
		(net "DMI_CPU0_PCH_RX_DN<5>")
	)
	(segment
		(start 346.462096 -63.821564)
		(end 346.4687 -63.821564)
		(width 0.13208)
		(layer "B.Cu")
		(net "DMI_CPU0_PCH_RX_DN<5>")
	)
	(segment
		(start 343.276682 -55.810658)
		(end 343.201498 -55.830978)
		(width 0.0889)
		(layer "B.Cu")
		(net "DMI_CPU0_PCH_RX_DN<5>")
	)
	(segment
		(start 345.397328 -60.510674)
		(end 345.953588 -60.741306)
		(width 0.13208)
		(layer "B.Cu")
		(net "DMI_CPU0_PCH_RX_DN<5>")
	)
	(segment
		(start 343.852754 -57.656984)
		(end 344.321638 -58.125868)
		(width 0.13208)
		(layer "B.Cu")
		(net "DMI_CPU0_PCH_RX_DN<5>")
	)
	(segment
		(start 343.550494 -55.968392)
		(end 343.276682 -55.810658)
		(width 0.0889)
		(layer "B.Cu")
		(net "DMI_CPU0_PCH_RX_DN<5>")
	)
	(segment
		(start 345.953588 -60.741306)
		(end 346.255848 -61.043566)
		(width 0.13208)
		(layer "B.Cu")
		(net "DMI_CPU0_PCH_RX_DN<5>")
	)
	(arc
		(start 343.225374 -56.15559)
		(mid 343.281769 -56.291842)
		(end 343.301066 -56.438038)
		(width 0.0889)
		(layer "B.Cu")
		(net "DMI_CPU0_PCH_RX_DN<5>")
	)
	(arc
		(start 343.201498 -55.830978)
		(mid 343.176437 -55.995995)
		(end 343.225374 -56.15559)
		(width 0.0889)
		(layer "B.Cu")
		(net "DMI_CPU0_PCH_RX_DN<5>")
	)
	(segment
		(start 342.19134 -55.498746)
		(end 341.921338 -55.028846)
		(width 0.13208)
		(layer "F.Cu")
		(net "DMI_CPU0_PCH_RX_DN<4>")
	)
	(via
		(at 341.921338 -55.028846)
		(size 0.4572)
		(drill 0.2032)
		(layers "F.Cu" "B.Cu")
		(net "DMI_CPU0_PCH_RX_DN<4>")
	)
	(segment
		(start 342.36025 -56.437022)
		(end 342.36025 -57.739534)
		(width 0.0889)
		(layer "B.Cu")
		(net "DMI_CPU0_PCH_RX_DN<4>")
	)
	(segment
		(start 344.018362 -60.772548)
		(end 344.427048 -61.181234)
		(width 0.13208)
		(layer "B.Cu")
		(net "DMI_CPU0_PCH_RX_DN<4>")
	)
	(segment
		(start 341.921338 -55.34152)
		(end 341.98687 -55.407052)
		(width 0.0889)
		(layer "B.Cu")
		(net "DMI_CPU0_PCH_RX_DN<4>")
	)
	(segment
		(start 342.696038 -58.026554)
		(end 342.711532 -58.042048)
		(width 0.0889)
		(layer "B.Cu")
		(net "DMI_CPU0_PCH_RX_DN<4>")
	)
	(segment
		(start 342.64727 -58.026554)
		(end 342.696038 -58.026554)
		(width 0.0889)
		(layer "B.Cu")
		(net "DMI_CPU0_PCH_RX_DN<4>")
	)
	(segment
		(start 343.011252 -58.341768)
		(end 344.018362 -60.772548)
		(width 0.13208)
		(layer "B.Cu")
		(net "DMI_CPU0_PCH_RX_DN<4>")
	)
	(segment
		(start 344.427048 -61.181234)
		(end 344.427048 -61.461904)
		(width 0.13208)
		(layer "B.Cu")
		(net "DMI_CPU0_PCH_RX_DN<4>")
	)
	(segment
		(start 342.36025 -57.739534)
		(end 342.64727 -58.026554)
		(width 0.0889)
		(layer "B.Cu")
		(net "DMI_CPU0_PCH_RX_DN<4>")
	)
	(segment
		(start 344.427048 -61.461904)
		(end 344.754708 -61.789564)
		(width 0.13208)
		(layer "B.Cu")
		(net "DMI_CPU0_PCH_RX_DN<4>")
	)
	(segment
		(start 342.711532 -58.042048)
		(end 343.011252 -58.341768)
		(width 0.13208)
		(layer "B.Cu")
		(net "DMI_CPU0_PCH_RX_DN<4>")
	)
	(segment
		(start 341.921338 -55.028846)
		(end 341.921338 -55.34152)
		(width 0.0889)
		(layer "B.Cu")
		(net "DMI_CPU0_PCH_RX_DN<4>")
	)
	(segment
		(start 342.411304 -55.686452)
		(end 342.410796 -55.686706)
		(width 0.0889)
		(layer "B.Cu")
		(net "DMI_CPU0_PCH_RX_DN<4>")
	)
	(arc
		(start 341.98687 -55.407052)
		(mid 341.997424 -55.40835)
		(end 342.007952 -55.409846)
		(width 0.0889)
		(layer "B.Cu")
		(net "DMI_CPU0_PCH_RX_DN<4>")
	)
	(arc
		(start 342.410542 -56.251094)
		(mid 342.376429 -56.329527)
		(end 342.361012 -56.413654)
		(width 0.0889)
		(layer "B.Cu")
		(net "DMI_CPU0_PCH_RX_DN<4>")
	)
	(arc
		(start 342.410796 -55.68569)
		(mid 342.41105 -55.686071)
		(end 342.411304 -55.686452)
		(width 0.0889)
		(layer "B.Cu")
		(net "DMI_CPU0_PCH_RX_DN<4>")
	)
	(arc
		(start 342.361012 -56.413654)
		(mid 342.360449 -56.425332)
		(end 342.36025 -56.437022)
		(width 0.0889)
		(layer "B.Cu")
		(net "DMI_CPU0_PCH_RX_DN<4>")
	)
	(arc
		(start 342.410796 -55.686706)
		(mid 342.486191 -55.968929)
		(end 342.410542 -56.251094)
		(width 0.0889)
		(layer "B.Cu")
		(net "DMI_CPU0_PCH_RX_DN<4>")
	)
	(arc
		(start 342.007952 -55.409846)
		(mid 342.240724 -55.502007)
		(end 342.410796 -55.68569)
		(width 0.0889)
		(layer "B.Cu")
		(net "DMI_CPU0_PCH_RX_DN<4>")
	)
	(segment
		(start 342.19134 -54.558946)
		(end 341.921338 -54.089046)
		(width 0.13208)
		(layer "F.Cu")
		(net "DMI_CPU0_PCH_RX_DN<3>")
	)
	(via
		(at 341.921338 -54.089046)
		(size 0.4572)
		(drill 0.2032)
		(layers "F.Cu" "B.Cu")
		(net "DMI_CPU0_PCH_RX_DN<3>")
	)
	(segment
		(start 342.05291 -59.190128)
		(end 342.05291 -59.441334)
		(width 0.13208)
		(layer "B.Cu")
		(net "DMI_CPU0_PCH_RX_DN<3>")
	)
	(segment
		(start 341.921338 -54.089046)
		(end 341.647526 -54.24678)
		(width 0.0889)
		(layer "B.Cu")
		(net "DMI_CPU0_PCH_RX_DN<3>")
	)
	(segment
		(start 341.560912 -56.858662)
		(end 341.560912 -57.857898)
		(width 0.0889)
		(layer "B.Cu")
		(net "DMI_CPU0_PCH_RX_DN<3>")
	)
	(segment
		(start 342.01862 -58.77306)
		(end 342.01862 -59.13374)
		(width 0.0889)
		(layer "B.Cu")
		(net "DMI_CPU0_PCH_RX_DN<3>")
	)
	(segment
		(start 341.560912 -57.857898)
		(end 342.01862 -58.77306)
		(width 0.0889)
		(layer "B.Cu")
		(net "DMI_CPU0_PCH_RX_DN<3>")
	)
	(segment
		(start 341.59825 -56.717946)
		(end 341.597996 -56.7182)
		(width 0.0889)
		(layer "B.Cu")
		(net "DMI_CPU0_PCH_RX_DN<3>")
	)
	(segment
		(start 342.598248 -60.965588)
		(end 342.598248 -62.76721)
		(width 0.13208)
		(layer "B.Cu")
		(net "DMI_CPU0_PCH_RX_DN<3>")
	)
	(segment
		(start 342.01862 -59.13374)
		(end 342.05291 -59.16803)
		(width 0.0889)
		(layer "B.Cu")
		(net "DMI_CPU0_PCH_RX_DN<3>")
	)
	(segment
		(start 342.82888 -63.484252)
		(end 343.166192 -63.821564)
		(width 0.13208)
		(layer "B.Cu")
		(net "DMI_CPU0_PCH_RX_DN<3>")
	)
	(segment
		(start 341.647526 -54.24678)
		(end 341.624666 -54.332124)
		(width 0.0889)
		(layer "B.Cu")
		(net "DMI_CPU0_PCH_RX_DN<3>")
	)
	(segment
		(start 342.05291 -59.16803)
		(end 342.05291 -59.190128)
		(width 0.0889)
		(layer "B.Cu")
		(net "DMI_CPU0_PCH_RX_DN<3>")
	)
	(segment
		(start 342.82888 -63.324232)
		(end 342.82888 -63.484252)
		(width 0.13208)
		(layer "B.Cu")
		(net "DMI_CPU0_PCH_RX_DN<3>")
	)
	(segment
		(start 342.598248 -62.76721)
		(end 342.82888 -63.324232)
		(width 0.13208)
		(layer "B.Cu")
		(net "DMI_CPU0_PCH_RX_DN<3>")
	)
	(segment
		(start 342.05291 -59.441334)
		(end 342.598248 -60.965588)
		(width 0.13208)
		(layer "B.Cu")
		(net "DMI_CPU0_PCH_RX_DN<3>")
	)
	(arc
		(start 341.632794 -54.351428)
		(mid 341.670572 -54.600727)
		(end 341.596218 -54.841648)
		(width 0.0889)
		(layer "B.Cu")
		(net "DMI_CPU0_PCH_RX_DN<3>")
	)
	(arc
		(start 341.596218 -54.841648)
		(mid 341.546177 -55.028846)
		(end 341.596218 -55.216044)
		(width 0.0889)
		(layer "B.Cu")
		(net "DMI_CPU0_PCH_RX_DN<3>")
	)
	(arc
		(start 341.596218 -55.781448)
		(mid 341.546177 -55.968646)
		(end 341.596218 -56.155844)
		(width 0.0889)
		(layer "B.Cu")
		(net "DMI_CPU0_PCH_RX_DN<3>")
	)
	(arc
		(start 341.596218 -56.155844)
		(mid 341.671889 -56.436609)
		(end 341.59825 -56.717946)
		(width 0.0889)
		(layer "B.Cu")
		(net "DMI_CPU0_PCH_RX_DN<3>")
	)
	(arc
		(start 341.597996 -56.7182)
		(mid 341.570308 -56.786019)
		(end 341.560912 -56.858662)
		(width 0.0889)
		(layer "B.Cu")
		(net "DMI_CPU0_PCH_RX_DN<3>")
	)
	(arc
		(start 341.596218 -55.216044)
		(mid 341.671892 -55.498746)
		(end 341.596218 -55.781448)
		(width 0.0889)
		(layer "B.Cu")
		(net "DMI_CPU0_PCH_RX_DN<3>")
	)
	(arc
		(start 341.624666 -54.332124)
		(mid 341.628819 -54.341738)
		(end 341.632794 -54.351428)
		(width 0.0889)
		(layer "B.Cu")
		(net "DMI_CPU0_PCH_RX_DN<3>")
	)
	(segment
		(start 340.562946 -55.498746)
		(end 340.290658 -55.028846)
		(width 0.13208)
		(layer "F.Cu")
		(net "DMI_CPU0_PCH_RX_DN<2>")
	)
	(via
		(at 340.290658 -55.028846)
		(size 0.4572)
		(drill 0.2032)
		(layers "F.Cu" "B.Cu")
		(net "DMI_CPU0_PCH_RX_DN<2>")
	)
	(segment
		(start 340.618826 -61.056774)
		(end 340.741 -61.178948)
		(width 0.13208)
		(layer "B.Cu")
		(net "DMI_CPU0_PCH_RX_DN<2>")
	)
	(segment
		(start 340.65337 -59.224926)
		(end 340.618826 -59.25947)
		(width 0.0889)
		(layer "B.Cu")
		(net "DMI_CPU0_PCH_RX_DN<2>")
	)
	(segment
		(start 340.618826 -59.270646)
		(end 340.618826 -61.056774)
		(width 0.13208)
		(layer "B.Cu")
		(net "DMI_CPU0_PCH_RX_DN<2>")
	)
	(segment
		(start 340.65337 -56.82996)
		(end 340.65337 -59.224926)
		(width 0.0889)
		(layer "B.Cu")
		(net "DMI_CPU0_PCH_RX_DN<2>")
	)
	(segment
		(start 340.741 -61.178948)
		(end 340.741 -61.454792)
		(width 0.13208)
		(layer "B.Cu")
		(net "DMI_CPU0_PCH_RX_DN<2>")
	)
	(segment
		(start 340.741 -61.454792)
		(end 340.406228 -61.789564)
		(width 0.13208)
		(layer "B.Cu")
		(net "DMI_CPU0_PCH_RX_DN<2>")
	)
	(segment
		(start 340.290658 -55.028846)
		(end 340.56447 -55.18658)
		(width 0.0889)
		(layer "B.Cu")
		(net "DMI_CPU0_PCH_RX_DN<2>")
	)
	(segment
		(start 340.56447 -55.18658)
		(end 340.58733 -55.271924)
		(width 0.0889)
		(layer "B.Cu")
		(net "DMI_CPU0_PCH_RX_DN<2>")
	)
	(segment
		(start 340.618826 -59.25947)
		(end 340.618826 -59.270646)
		(width 0.0889)
		(layer "B.Cu")
		(net "DMI_CPU0_PCH_RX_DN<2>")
	)
	(arc
		(start 340.616032 -56.72074)
		(mid 340.632959 -56.75402)
		(end 340.646512 -56.788812)
		(width 0.0889)
		(layer "B.Cu")
		(net "DMI_CPU0_PCH_RX_DN<2>")
	)
	(arc
		(start 340.58733 -55.271924)
		(mid 340.583177 -55.281538)
		(end 340.579202 -55.291228)
		(width 0.0889)
		(layer "B.Cu")
		(net "DMI_CPU0_PCH_RX_DN<2>")
	)
	(arc
		(start 340.646512 -56.788812)
		(mid 340.651618 -56.809107)
		(end 340.65337 -56.82996)
		(width 0.0889)
		(layer "B.Cu")
		(net "DMI_CPU0_PCH_RX_DN<2>")
	)
	(arc
		(start 340.615778 -56.155844)
		(mid 340.540358 -56.438321)
		(end 340.616032 -56.72074)
		(width 0.0889)
		(layer "B.Cu")
		(net "DMI_CPU0_PCH_RX_DN<2>")
	)
	(arc
		(start 340.579202 -55.291228)
		(mid 340.541424 -55.540527)
		(end 340.615778 -55.781448)
		(width 0.0889)
		(layer "B.Cu")
		(net "DMI_CPU0_PCH_RX_DN<2>")
	)
	(arc
		(start 340.615778 -55.781448)
		(mid 340.665819 -55.968646)
		(end 340.615778 -56.155844)
		(width 0.0889)
		(layer "B.Cu")
		(net "DMI_CPU0_PCH_RX_DN<2>")
	)
	(segment
		(start 340.562946 -56.438546)
		(end 340.290658 -55.968646)
		(width 0.13208)
		(layer "F.Cu")
		(net "DMI_CPU0_PCH_RX_DN<1>")
	)
	(via
		(at 340.290658 -55.968646)
		(size 0.4572)
		(drill 0.2032)
		(layers "F.Cu" "B.Cu")
		(net "DMI_CPU0_PCH_RX_DN<1>")
	)
	(segment
		(start 338.940648 -61.197236)
		(end 339.192108 -60.590684)
		(width 0.13208)
		(layer "B.Cu")
		(net "DMI_CPU0_PCH_RX_DN<1>")
	)
	(segment
		(start 339.914484 -58.758582)
		(end 339.92566 -58.747406)
		(width 0.13208)
		(layer "B.Cu")
		(net "DMI_CPU0_PCH_RX_DN<1>")
	)
	(segment
		(start 339.611716 -59.93638)
		(end 339.611716 -59.756548)
		(width 0.13208)
		(layer "B.Cu")
		(net "DMI_CPU0_PCH_RX_DN<1>")
	)
	(segment
		(start 339.4456 -60.337446)
		(end 339.611716 -59.93638)
		(width 0.13208)
		(layer "B.Cu")
		(net "DMI_CPU0_PCH_RX_DN<1>")
	)
	(segment
		(start 340.094824 -56.37784)
		(end 340.011512 -56.23306)
		(width 0.0889)
		(layer "B.Cu")
		(net "DMI_CPU0_PCH_RX_DN<1>")
	)
	(segment
		(start 340.011512 -56.23306)
		(end 340.044024 -56.11114)
		(width 0.0889)
		(layer "B.Cu")
		(net "DMI_CPU0_PCH_RX_DN<1>")
	)
	(segment
		(start 340.35746 -66.158364)
		(end 340.0044 -65.805304)
		(width 0.13208)
		(layer "B.Cu")
		(net "DMI_CPU0_PCH_RX_DN<1>")
	)
	(segment
		(start 339.192108 -60.590684)
		(end 339.4456 -60.337446)
		(width 0.13208)
		(layer "B.Cu")
		(net "DMI_CPU0_PCH_RX_DN<1>")
	)
	(segment
		(start 339.89137 -58.599578)
		(end 339.89137 -57.048654)
		(width 0.0889)
		(layer "B.Cu")
		(net "DMI_CPU0_PCH_RX_DN<1>")
	)
	(segment
		(start 340.0044 -64.382904)
		(end 338.940648 -61.814964)
		(width 0.13208)
		(layer "B.Cu")
		(net "DMI_CPU0_PCH_RX_DN<1>")
	)
	(segment
		(start 339.92566 -58.633868)
		(end 339.89137 -58.599578)
		(width 0.0889)
		(layer "B.Cu")
		(net "DMI_CPU0_PCH_RX_DN<1>")
	)
	(segment
		(start 339.89137 -57.048654)
		(end 340.094824 -56.8452)
		(width 0.0889)
		(layer "B.Cu")
		(net "DMI_CPU0_PCH_RX_DN<1>")
	)
	(segment
		(start 340.0044 -65.805304)
		(end 340.0044 -64.382904)
		(width 0.13208)
		(layer "B.Cu")
		(net "DMI_CPU0_PCH_RX_DN<1>")
	)
	(segment
		(start 339.92566 -58.655966)
		(end 339.92566 -58.633868)
		(width 0.0889)
		(layer "B.Cu")
		(net "DMI_CPU0_PCH_RX_DN<1>")
	)
	(segment
		(start 340.044024 -56.11114)
		(end 340.290658 -55.968646)
		(width 0.0889)
		(layer "B.Cu")
		(net "DMI_CPU0_PCH_RX_DN<1>")
	)
	(segment
		(start 338.940648 -61.814964)
		(end 338.940648 -61.197236)
		(width 0.13208)
		(layer "B.Cu")
		(net "DMI_CPU0_PCH_RX_DN<1>")
	)
	(segment
		(start 339.92566 -58.747406)
		(end 339.92566 -58.655966)
		(width 0.13208)
		(layer "B.Cu")
		(net "DMI_CPU0_PCH_RX_DN<1>")
	)
	(segment
		(start 339.611716 -59.756548)
		(end 339.914484 -58.758582)
		(width 0.13208)
		(layer "B.Cu")
		(net "DMI_CPU0_PCH_RX_DN<1>")
	)
	(segment
		(start 340.094824 -56.8452)
		(end 340.094824 -56.37784)
		(width 0.0889)
		(layer "B.Cu")
		(net "DMI_CPU0_PCH_RX_DN<1>")
	)
	(segment
		(start 339.587078 -54.747668)
		(end 339.675216 -54.900068)
		(width 0.13208)
		(layer "F.Cu")
		(net "DMI_CPU0_PCH_RX_DN<0>")
	)
	(segment
		(start 339.477858 -54.558946)
		(end 339.587078 -54.747668)
		(width 0.13208)
		(layer "F.Cu")
		(net "DMI_CPU0_PCH_RX_DN<0>")
	)
	(segment
		(start 339.749638 -55.028846)
		(end 339.748876 -55.028846)
		(width 0.13208)
		(layer "F.Cu")
		(net "DMI_CPU0_PCH_RX_DN<0>")
	)
	(segment
		(start 339.675216 -54.900068)
		(end 339.749638 -55.028846)
		(width 0.13208)
		(layer "F.Cu")
		(net "DMI_CPU0_PCH_RX_DN<0>")
	)
	(via
		(at 339.477858 -54.558946)
		(size 0.4572)
		(drill 0.2032)
		(layers "F.Cu" "B.Cu")
		(net "DMI_CPU0_PCH_RX_DN<0>")
	)
	(segment
		(start 337.18627 -61.516006)
		(end 337.220814 -61.481462)
		(width 0.0889)
		(layer "B.Cu")
		(net "DMI_CPU0_PCH_RX_DN<0>")
	)
	(segment
		(start 337.574382 -60.577222)
		(end 337.574382 -60.100464)
		(width 0.0889)
		(layer "B.Cu")
		(net "DMI_CPU0_PCH_RX_DN<0>")
	)
	(segment
		(start 337.18627 -61.538104)
		(end 337.18627 -61.516006)
		(width 0.0889)
		(layer "B.Cu")
		(net "DMI_CPU0_PCH_RX_DN<0>")
	)
	(segment
		(start 337.218782 -64.049148)
		(end 337.546442 -63.721488)
		(width 0.13208)
		(layer "B.Cu")
		(net "DMI_CPU0_PCH_RX_DN<0>")
	)
	(segment
		(start 337.546442 -63.721488)
		(end 337.546442 -63.39586)
		(width 0.13208)
		(layer "B.Cu")
		(net "DMI_CPU0_PCH_RX_DN<0>")
	)
	(segment
		(start 337.574636 -60.10021)
		(end 337.574636 -59.238134)
		(width 0.0889)
		(layer "B.Cu")
		(net "DMI_CPU0_PCH_RX_DN<0>")
	)
	(segment
		(start 337.18627 -62.525656)
		(end 337.18627 -61.538104)
		(width 0.13208)
		(layer "B.Cu")
		(net "DMI_CPU0_PCH_RX_DN<0>")
	)
	(segment
		(start 337.546442 -63.39586)
		(end 337.18627 -62.525656)
		(width 0.13208)
		(layer "B.Cu")
		(net "DMI_CPU0_PCH_RX_DN<0>")
	)
	(segment
		(start 337.574382 -60.100464)
		(end 337.574636 -60.10021)
		(width 0.0889)
		(layer "B.Cu")
		(net "DMI_CPU0_PCH_RX_DN<0>")
	)
	(segment
		(start 339.388958 -54.93385)
		(end 339.477858 -54.84495)
		(width 0.0889)
		(layer "B.Cu")
		(net "DMI_CPU0_PCH_RX_DN<0>")
	)
	(segment
		(start 338.912962 -57.899808)
		(end 338.912962 -55.205122)
		(width 0.0889)
		(layer "B.Cu")
		(net "DMI_CPU0_PCH_RX_DN<0>")
	)
	(segment
		(start 337.220814 -61.481462)
		(end 337.220814 -60.93079)
		(width 0.0889)
		(layer "B.Cu")
		(net "DMI_CPU0_PCH_RX_DN<0>")
	)
	(segment
		(start 339.184234 -54.93385)
		(end 339.388958 -54.93385)
		(width 0.0889)
		(layer "B.Cu")
		(net "DMI_CPU0_PCH_RX_DN<0>")
	)
	(segment
		(start 339.477858 -54.84495)
		(end 339.477858 -54.558946)
		(width 0.0889)
		(layer "B.Cu")
		(net "DMI_CPU0_PCH_RX_DN<0>")
	)
	(segment
		(start 338.912962 -55.205122)
		(end 339.184234 -54.93385)
		(width 0.0889)
		(layer "B.Cu")
		(net "DMI_CPU0_PCH_RX_DN<0>")
	)
	(segment
		(start 337.574636 -59.238134)
		(end 338.912962 -57.899808)
		(width 0.0889)
		(layer "B.Cu")
		(net "DMI_CPU0_PCH_RX_DN<0>")
	)
	(segment
		(start 337.220814 -60.93079)
		(end 337.574382 -60.577222)
		(width 0.0889)
		(layer "B.Cu")
		(net "DMI_CPU0_PCH_RX_DN<0>")
	)
	(segment
		(start 358.640634 -228.1809)
		(end 358.640634 -227.64496)
		(width 0.13208)
		(layer "F.Cu")
		(net "DMI_CPU0_PCH_RX_C_DP<7>")
	)
	(segment
		(start 353.49688 -67.802506)
		(end 351.75571 -66.061336)
		(width 0.13208)
		(layer "B.Cu")
		(net "DMI_CPU0_PCH_RX_C_DP<7>")
	)
	(segment
		(start 351.255584 -64.854074)
		(end 350.90989 -64.50838)
		(width 0.13208)
		(layer "B.Cu")
		(net "DMI_CPU0_PCH_RX_C_DP<7>")
	)
	(segment
		(start 350.90989 -64.50838)
		(end 350.270064 -64.50838)
		(width 0.13208)
		(layer "B.Cu")
		(net "DMI_CPU0_PCH_RX_C_DP<7>")
	)
	(segment
		(start 345.889834 -84.39785)
		(end 345.587574 -84.09559)
		(width 0.13208)
		(layer "B.Cu")
		(net "DMI_CPU0_PCH_RX_C_DP<7>")
	)
	(segment
		(start 345.587574 -81.752948)
		(end 351.479866 -75.860656)
		(width 0.13208)
		(layer "B.Cu")
		(net "DMI_CPU0_PCH_RX_C_DP<7>")
	)
	(segment
		(start 345.587574 -84.09559)
		(end 345.587574 -81.752948)
		(width 0.13208)
		(layer "B.Cu")
		(net "DMI_CPU0_PCH_RX_C_DP<7>")
	)
	(segment
		(start 353.49688 -70.990714)
		(end 353.49688 -67.802506)
		(width 0.13208)
		(layer "B.Cu")
		(net "DMI_CPU0_PCH_RX_C_DP<7>")
	)
	(segment
		(start 351.75571 -66.061336)
		(end 351.255584 -64.854074)
		(width 0.13208)
		(layer "B.Cu")
		(net "DMI_CPU0_PCH_RX_C_DP<7>")
	)
	(segment
		(start 351.479866 -75.860656)
		(end 353.49688 -70.990714)
		(width 0.13208)
		(layer "B.Cu")
		(net "DMI_CPU0_PCH_RX_C_DP<7>")
	)
	(segment
		(start 350.270064 -64.50838)
		(end 349.942404 -64.18072)
		(width 0.13208)
		(layer "B.Cu")
		(net "DMI_CPU0_PCH_RX_C_DP<7>")
	)
	(segment
		(start 359.862374 -226.507294)
		(end 359.863136 -226.506786)
		(width 0.0889)
		(layer "In6.Cu")
		(net "DMI_CPU0_PCH_RX_C_DP<7>")
	)
	(segment
		(start 367.227866 -208.203038)
		(end 367.458244 -206.89697)
		(width 0.14732)
		(layer "In6.Cu")
		(net "DMI_CPU0_PCH_RX_C_DP<7>")
	)
	(segment
		(start 364.552992 -221.628462)
		(end 364.561882 -221.623382)
		(width 0.0889)
		(layer "In6.Cu")
		(net "DMI_CPU0_PCH_RX_C_DP<7>")
	)
	(segment
		(start 359.854246 -226.511866)
		(end 359.859834 -226.508818)
		(width 0.0889)
		(layer "In6.Cu")
		(net "DMI_CPU0_PCH_RX_C_DP<7>")
	)
	(segment
		(start 376.361198 -196.617082)
		(end 383.078482 -187.02401)
		(width 0.14732)
		(layer "In6.Cu")
		(net "DMI_CPU0_PCH_RX_C_DP<7>")
	)
	(segment
		(start 364.374684 -220.32849)
		(end 364.374684 -220.311218)
		(width 0.0889)
		(layer "In6.Cu")
		(net "DMI_CPU0_PCH_RX_C_DP<7>")
	)
	(segment
		(start 360.333036 -224.7138)
		(end 360.324146 -224.70872)
		(width 0.0889)
		(layer "In6.Cu")
		(net "DMI_CPU0_PCH_RX_C_DP<7>")
	)
	(segment
		(start 362.964984 -222.780098)
		(end 362.964984 -222.761556)
		(width 0.0889)
		(layer "In6.Cu")
		(net "DMI_CPU0_PCH_RX_C_DP<7>")
	)
	(segment
		(start 363.526832 -222.437198)
		(end 363.541564 -222.445834)
		(width 0.0889)
		(layer "In6.Cu")
		(net "DMI_CPU0_PCH_RX_C_DP<7>")
	)
	(segment
		(start 367.458244 -206.89697)
		(end 373.016526 -198.958962)
		(width 0.14732)
		(layer "In6.Cu")
		(net "DMI_CPU0_PCH_RX_C_DP<7>")
	)
	(segment
		(start 365.501682 -218.367864)
		(end 365.507778 -218.364308)
		(width 0.0889)
		(layer "In6.Cu")
		(net "DMI_CPU0_PCH_RX_C_DP<7>")
	)
	(segment
		(start 365.501936 -217.388694)
		(end 365.493046 -217.383614)
		(width 0.0889)
		(layer "In6.Cu")
		(net "DMI_CPU0_PCH_RX_C_DP<7>")
	)
	(segment
		(start 365.023146 -219.18676)
		(end 365.032036 -219.18168)
		(width 0.0889)
		(layer "In6.Cu")
		(net "DMI_CPU0_PCH_RX_C_DP<7>")
	)
	(segment
		(start 345.595194 -85.526626)
		(end 345.595194 -84.69249)
		(width 0.14732)
		(layer "In6.Cu")
		(net "DMI_CPU0_PCH_RX_C_DP<7>")
	)
	(segment
		(start 358.640634 -227.64496)
		(end 358.797098 -227.373942)
		(width 0.0889)
		(layer "In6.Cu")
		(net "DMI_CPU0_PCH_RX_C_DP<7>")
	)
	(segment
		(start 364.37443 -221.963234)
		(end 364.37443 -221.94774)
		(width 0.0889)
		(layer "In6.Cu")
		(net "DMI_CPU0_PCH_RX_C_DP<7>")
	)
	(segment
		(start 359.859834 -226.508818)
		(end 359.860596 -226.50831)
		(width 0.0889)
		(layer "In6.Cu")
		(net "DMI_CPU0_PCH_RX_C_DP<7>")
	)
	(segment
		(start 364.844584 -221.133924)
		(end 364.844584 -221.1197)
		(width 0.0889)
		(layer "In6.Cu")
		(net "DMI_CPU0_PCH_RX_C_DP<7>")
	)
	(segment
		(start 346.02166 -87.248746)
		(end 345.595194 -85.526626)
		(width 0.14732)
		(layer "In6.Cu")
		(net "DMI_CPU0_PCH_RX_C_DP<7>")
	)
	(segment
		(start 358.797098 -227.373942)
		(end 358.885998 -227.35032)
		(width 0.0889)
		(layer "In6.Cu")
		(net "DMI_CPU0_PCH_RX_C_DP<7>")
	)
	(segment
		(start 365.31423 -218.707716)
		(end 365.31423 -218.692222)
		(width 0.0889)
		(layer "In6.Cu")
		(net "DMI_CPU0_PCH_RX_C_DP<7>")
	)
	(segment
		(start 367.185956 -214.395304)
		(end 367.185956 -211.515452)
		(width 0.0889)
		(layer "In6.Cu")
		(net "DMI_CPU0_PCH_RX_C_DP<7>")
	)
	(segment
		(start 360.61523 -225.225356)
		(end 360.61523 -225.187764)
		(width 0.0889)
		(layer "In6.Cu")
		(net "DMI_CPU0_PCH_RX_C_DP<7>")
	)
	(segment
		(start 364.561882 -221.623382)
		(end 364.567978 -221.619826)
		(width 0.0889)
		(layer "In6.Cu")
		(net "DMI_CPU0_PCH_RX_C_DP<7>")
	)
	(segment
		(start 359.393236 -227.320602)
		(end 359.399332 -227.317046)
		(width 0.0889)
		(layer "In6.Cu")
		(net "DMI_CPU0_PCH_RX_C_DP<7>")
	)
	(segment
		(start 367.22812 -211.258912)
		(end 367.227866 -211.258658)
		(width 0.14732)
		(layer "In6.Cu")
		(net "DMI_CPU0_PCH_RX_C_DP<7>")
	)
	(segment
		(start 367.185956 -211.515452)
		(end 367.22812 -211.473288)
		(width 0.0889)
		(layer "In6.Cu")
		(net "DMI_CPU0_PCH_RX_C_DP<7>")
	)
	(segment
		(start 365.492792 -218.372944)
		(end 365.501682 -218.367864)
		(width 0.0889)
		(layer "In6.Cu")
		(net "DMI_CPU0_PCH_RX_C_DP<7>")
	)
	(segment
		(start 366.254284 -215.44661)
		(end 366.254284 -215.428068)
		(width 0.0889)
		(layer "In6.Cu")
		(net "DMI_CPU0_PCH_RX_C_DP<7>")
	)
	(segment
		(start 383.078482 -187.02401)
		(end 384.930396 -176.520348)
		(width 0.14732)
		(layer "In6.Cu")
		(net "DMI_CPU0_PCH_RX_C_DP<7>")
	)
	(segment
		(start 359.860596 -226.50831)
		(end 359.862374 -226.507294)
		(width 0.0889)
		(layer "In6.Cu")
		(net "DMI_CPU0_PCH_RX_C_DP<7>")
	)
	(segment
		(start 384.930396 -176.520348)
		(end 380.825756 -153.24201)
		(width 0.14732)
		(layer "In6.Cu")
		(net "DMI_CPU0_PCH_RX_C_DP<7>")
	)
	(segment
		(start 364.561882 -219.995496)
		(end 364.562644 -219.994988)
		(width 0.0889)
		(layer "In6.Cu")
		(net "DMI_CPU0_PCH_RX_C_DP<7>")
	)
	(segment
		(start 365.493046 -216.745058)
		(end 365.498634 -216.74201)
		(width 0.0889)
		(layer "In6.Cu")
		(net "DMI_CPU0_PCH_RX_C_DP<7>")
	)
	(segment
		(start 360.615484 -223.585532)
		(end 360.615484 -223.56699)
		(width 0.0889)
		(layer "In6.Cu")
		(net "DMI_CPU0_PCH_RX_C_DP<7>")
	)
	(segment
		(start 365.501174 -216.740486)
		(end 365.501936 -216.739978)
		(width 0.0889)
		(layer "In6.Cu")
		(net "DMI_CPU0_PCH_RX_C_DP<7>")
	)
	(segment
		(start 360.324146 -224.070164)
		(end 360.333036 -224.065084)
		(width 0.0889)
		(layer "In6.Cu")
		(net "DMI_CPU0_PCH_RX_C_DP<7>")
	)
	(segment
		(start 365.498634 -216.74201)
		(end 365.499396 -216.741502)
		(width 0.0889)
		(layer "In6.Cu")
		(net "DMI_CPU0_PCH_RX_C_DP<7>")
	)
	(segment
		(start 373.016526 -198.958962)
		(end 376.361198 -196.617082)
		(width 0.14732)
		(layer "In6.Cu")
		(net "DMI_CPU0_PCH_RX_C_DP<7>")
	)
	(segment
		(start 366.55883 -215.022684)
		(end 367.185956 -214.395304)
		(width 0.0889)
		(layer "In6.Cu")
		(net "DMI_CPU0_PCH_RX_C_DP<7>")
	)
	(segment
		(start 367.22812 -211.473288)
		(end 367.22812 -211.45119)
		(width 0.0889)
		(layer "In6.Cu")
		(net "DMI_CPU0_PCH_RX_C_DP<7>")
	)
	(segment
		(start 345.595194 -84.69249)
		(end 345.889834 -84.39785)
		(width 0.14732)
		(layer "In6.Cu")
		(net "DMI_CPU0_PCH_RX_C_DP<7>")
	)
	(segment
		(start 365.962946 -215.931242)
		(end 365.971836 -215.926162)
		(width 0.0889)
		(layer "In6.Cu")
		(net "DMI_CPU0_PCH_RX_C_DP<7>")
	)
	(segment
		(start 361.732322 -223.257364)
		(end 361.742736 -223.251268)
		(width 0.0889)
		(layer "In6.Cu")
		(net "DMI_CPU0_PCH_RX_C_DP<7>")
	)
	(segment
		(start 367.227866 -211.258658)
		(end 367.227866 -208.203038)
		(width 0.14732)
		(layer "In6.Cu")
		(net "DMI_CPU0_PCH_RX_C_DP<7>")
	)
	(segment
		(start 380.825756 -153.24201)
		(end 346.02166 -87.248746)
		(width 0.14732)
		(layer "In6.Cu")
		(net "DMI_CPU0_PCH_RX_C_DP<7>")
	)
	(segment
		(start 363.143546 -222.442278)
		(end 363.152436 -222.437198)
		(width 0.0889)
		(layer "In6.Cu")
		(net "DMI_CPU0_PCH_RX_C_DP<7>")
	)
	(segment
		(start 365.499396 -216.741502)
		(end 365.501174 -216.740486)
		(width 0.0889)
		(layer "In6.Cu")
		(net "DMI_CPU0_PCH_RX_C_DP<7>")
	)
	(segment
		(start 364.562644 -219.994988)
		(end 364.567978 -219.99194)
		(width 0.0889)
		(layer "In6.Cu")
		(net "DMI_CPU0_PCH_RX_C_DP<7>")
	)
	(segment
		(start 360.324146 -225.69805)
		(end 360.333036 -225.69297)
		(width 0.0889)
		(layer "In6.Cu")
		(net "DMI_CPU0_PCH_RX_C_DP<7>")
	)
	(segment
		(start 365.784384 -217.878406)
		(end 365.784384 -217.859864)
		(width 0.0889)
		(layer "In6.Cu")
		(net "DMI_CPU0_PCH_RX_C_DP<7>")
	)
	(segment
		(start 367.22812 -211.45119)
		(end 367.22812 -211.258912)
		(width 0.14732)
		(layer "In6.Cu")
		(net "DMI_CPU0_PCH_RX_C_DP<7>")
	)
	(segment
		(start 365.784384 -216.260426)
		(end 365.784384 -216.25052)
		(width 0.0889)
		(layer "In6.Cu")
		(net "DMI_CPU0_PCH_RX_C_DP<7>")
	)
	(segment
		(start 360.145584 -226.027234)
		(end 360.145584 -226.017328)
		(width 0.0889)
		(layer "In6.Cu")
		(net "DMI_CPU0_PCH_RX_C_DP<7>")
	)
	(arc
		(start 364.37443 -221.94774)
		(mid 364.422109 -221.76484)
		(end 364.552992 -221.628462)
		(width 0.0889)
		(layer "In6.Cu")
		(net "DMI_CPU0_PCH_RX_C_DP<7>")
	)
	(arc
		(start 365.507778 -218.364308)
		(mid 365.710365 -218.157957)
		(end 365.784384 -217.878406)
		(width 0.0889)
		(layer "In6.Cu")
		(net "DMI_CPU0_PCH_RX_C_DP<7>")
	)
	(arc
		(start 364.561882 -220.644212)
		(mid 364.426949 -220.510858)
		(end 364.374684 -220.32849)
		(width 0.0889)
		(layer "In6.Cu")
		(net "DMI_CPU0_PCH_RX_C_DP<7>")
	)
	(arc
		(start 363.541564 -222.445834)
		(mid 363.818039 -222.513154)
		(end 364.092236 -222.437198)
		(width 0.0889)
		(layer "In6.Cu")
		(net "DMI_CPU0_PCH_RX_C_DP<7>")
	)
	(arc
		(start 359.399332 -227.317046)
		(mid 359.601745 -227.110633)
		(end 359.675684 -226.831144)
		(width 0.0889)
		(layer "In6.Cu")
		(net "DMI_CPU0_PCH_RX_C_DP<7>")
	)
	(arc
		(start 362.682536 -223.251268)
		(mid 362.884822 -223.052287)
		(end 362.964984 -222.780098)
		(width 0.0889)
		(layer "In6.Cu")
		(net "DMI_CPU0_PCH_RX_C_DP<7>")
	)
	(arc
		(start 366.475772 -215.09101)
		(mid 366.518935 -215.058832)
		(end 366.55883 -215.022684)
		(width 0.0889)
		(layer "In6.Cu")
		(net "DMI_CPU0_PCH_RX_C_DP<7>")
	)
	(arc
		(start 360.333036 -224.065084)
		(mid 360.537371 -223.862479)
		(end 360.615484 -223.585532)
		(width 0.0889)
		(layer "In6.Cu")
		(net "DMI_CPU0_PCH_RX_C_DP<7>")
	)
	(arc
		(start 365.971836 -215.926162)
		(mid 366.176171 -215.723557)
		(end 366.254284 -215.44661)
		(width 0.0889)
		(layer "In6.Cu")
		(net "DMI_CPU0_PCH_RX_C_DP<7>")
	)
	(arc
		(start 360.145584 -224.382838)
		(mid 360.194858 -224.203668)
		(end 360.324146 -224.070164)
		(width 0.0889)
		(layer "In6.Cu")
		(net "DMI_CPU0_PCH_RX_C_DP<7>")
	)
	(arc
		(start 360.333036 -225.69297)
		(mid 360.534318 -225.495483)
		(end 360.61523 -225.225356)
		(width 0.0889)
		(layer "In6.Cu")
		(net "DMI_CPU0_PCH_RX_C_DP<7>")
	)
	(arc
		(start 360.145584 -224.399602)
		(mid 360.14549 -224.39122)
		(end 360.145584 -224.382838)
		(width 0.0889)
		(layer "In6.Cu")
		(net "DMI_CPU0_PCH_RX_C_DP<7>")
	)
	(arc
		(start 363.152436 -222.437198)
		(mid 363.339634 -222.387055)
		(end 363.526832 -222.437198)
		(width 0.0889)
		(layer "In6.Cu")
		(net "DMI_CPU0_PCH_RX_C_DP<7>")
	)
	(arc
		(start 361.177078 -223.251268)
		(mid 361.453891 -223.327104)
		(end 361.732322 -223.257364)
		(width 0.0889)
		(layer "In6.Cu")
		(net "DMI_CPU0_PCH_RX_C_DP<7>")
	)
	(arc
		(start 360.61523 -225.187764)
		(mid 360.53586 -224.91403)
		(end 360.333036 -224.7138)
		(width 0.0889)
		(layer "In6.Cu")
		(net "DMI_CPU0_PCH_RX_C_DP<7>")
	)
	(arc
		(start 364.567978 -221.619826)
		(mid 364.770565 -221.413475)
		(end 364.844584 -221.133924)
		(width 0.0889)
		(layer "In6.Cu")
		(net "DMI_CPU0_PCH_RX_C_DP<7>")
	)
	(arc
		(start 358.90581 -227.358448)
		(mid 359.153821 -227.394913)
		(end 359.393236 -227.320602)
		(width 0.0889)
		(layer "In6.Cu")
		(net "DMI_CPU0_PCH_RX_C_DP<7>")
	)
	(arc
		(start 362.964984 -222.761556)
		(mid 363.012663 -222.578656)
		(end 363.143546 -222.442278)
		(width 0.0889)
		(layer "In6.Cu")
		(net "DMI_CPU0_PCH_RX_C_DP<7>")
	)
	(arc
		(start 359.863136 -226.506786)
		(mid 360.067471 -226.304181)
		(end 360.145584 -226.027234)
		(width 0.0889)
		(layer "In6.Cu")
		(net "DMI_CPU0_PCH_RX_C_DP<7>")
	)
	(arc
		(start 365.032036 -219.18168)
		(mid 365.234859 -218.981449)
		(end 365.31423 -218.707716)
		(width 0.0889)
		(layer "In6.Cu")
		(net "DMI_CPU0_PCH_RX_C_DP<7>")
	)
	(arc
		(start 366.441482 -215.112346)
		(mid 366.458817 -215.101983)
		(end 366.475772 -215.09101)
		(width 0.0889)
		(layer "In6.Cu")
		(net "DMI_CPU0_PCH_RX_C_DP<7>")
	)
	(arc
		(start 364.567978 -219.99194)
		(mid 364.770565 -219.785589)
		(end 364.844584 -219.506038)
		(width 0.0889)
		(layer "In6.Cu")
		(net "DMI_CPU0_PCH_RX_C_DP<7>")
	)
	(arc
		(start 366.254284 -215.428068)
		(mid 366.306554 -215.245703)
		(end 366.441482 -215.112346)
		(width 0.0889)
		(layer "In6.Cu")
		(net "DMI_CPU0_PCH_RX_C_DP<7>")
	)
	(arc
		(start 360.145584 -226.017328)
		(mid 360.145636 -226.009961)
		(end 360.145838 -226.002596)
		(width 0.0889)
		(layer "In6.Cu")
		(net "DMI_CPU0_PCH_RX_C_DP<7>")
	)
	(arc
		(start 360.615484 -223.56699)
		(mid 360.667754 -223.384625)
		(end 360.802682 -223.251268)
		(width 0.0889)
		(layer "In6.Cu")
		(net "DMI_CPU0_PCH_RX_C_DP<7>")
	)
	(arc
		(start 365.31423 -218.692222)
		(mid 365.361909 -218.509322)
		(end 365.492792 -218.372944)
		(width 0.0889)
		(layer "In6.Cu")
		(net "DMI_CPU0_PCH_RX_C_DP<7>")
	)
	(arc
		(start 364.844584 -219.506038)
		(mid 364.892263 -219.323138)
		(end 365.023146 -219.18676)
		(width 0.0889)
		(layer "In6.Cu")
		(net "DMI_CPU0_PCH_RX_C_DP<7>")
	)
	(arc
		(start 364.092236 -222.437198)
		(mid 364.295059 -222.236967)
		(end 364.37443 -221.963234)
		(width 0.0889)
		(layer "In6.Cu")
		(net "DMI_CPU0_PCH_RX_C_DP<7>")
	)
	(arc
		(start 365.784384 -217.859864)
		(mid 365.704222 -217.587675)
		(end 365.501936 -217.388694)
		(width 0.0889)
		(layer "In6.Cu")
		(net "DMI_CPU0_PCH_RX_C_DP<7>")
	)
	(arc
		(start 358.885998 -227.35032)
		(mid 358.895865 -227.354479)
		(end 358.90581 -227.358448)
		(width 0.0889)
		(layer "In6.Cu")
		(net "DMI_CPU0_PCH_RX_C_DP<7>")
	)
	(arc
		(start 360.802682 -223.251268)
		(mid 360.98988 -223.201125)
		(end 361.177078 -223.251268)
		(width 0.0889)
		(layer "In6.Cu")
		(net "DMI_CPU0_PCH_RX_C_DP<7>")
	)
	(arc
		(start 360.145838 -226.002596)
		(mid 360.196892 -225.828016)
		(end 360.324146 -225.69805)
		(width 0.0889)
		(layer "In6.Cu")
		(net "DMI_CPU0_PCH_RX_C_DP<7>")
	)
	(arc
		(start 361.742736 -223.251268)
		(mid 361.929934 -223.201125)
		(end 362.117132 -223.251268)
		(width 0.0889)
		(layer "In6.Cu")
		(net "DMI_CPU0_PCH_RX_C_DP<7>")
	)
	(arc
		(start 365.501936 -216.739978)
		(mid 365.706271 -216.537373)
		(end 365.784384 -216.260426)
		(width 0.0889)
		(layer "In6.Cu")
		(net "DMI_CPU0_PCH_RX_C_DP<7>")
	)
	(arc
		(start 359.675684 -226.831144)
		(mid 359.723363 -226.648244)
		(end 359.854246 -226.511866)
		(width 0.0889)
		(layer "In6.Cu")
		(net "DMI_CPU0_PCH_RX_C_DP<7>")
	)
	(arc
		(start 365.784384 -216.25052)
		(mid 365.832063 -216.06762)
		(end 365.962946 -215.931242)
		(width 0.0889)
		(layer "In6.Cu")
		(net "DMI_CPU0_PCH_RX_C_DP<7>")
	)
	(arc
		(start 365.493046 -217.383614)
		(mid 365.314449 -217.064336)
		(end 365.493046 -216.745058)
		(width 0.0889)
		(layer "In6.Cu")
		(net "DMI_CPU0_PCH_RX_C_DP<7>")
	)
	(arc
		(start 360.324146 -224.70872)
		(mid 360.195659 -224.576806)
		(end 360.145584 -224.399602)
		(width 0.0889)
		(layer "In6.Cu")
		(net "DMI_CPU0_PCH_RX_C_DP<7>")
	)
	(arc
		(start 362.117132 -223.251268)
		(mid 362.399834 -223.32701)
		(end 362.682536 -223.251268)
		(width 0.0889)
		(layer "In6.Cu")
		(net "DMI_CPU0_PCH_RX_C_DP<7>")
	)
	(arc
		(start 364.374684 -220.311218)
		(mid 364.426954 -220.128853)
		(end 364.561882 -219.995496)
		(width 0.0889)
		(layer "In6.Cu")
		(net "DMI_CPU0_PCH_RX_C_DP<7>")
	)
	(arc
		(start 364.844584 -221.1197)
		(mid 364.765365 -220.845015)
		(end 364.561882 -220.644212)
		(width 0.0889)
		(layer "In6.Cu")
		(net "DMI_CPU0_PCH_RX_C_DP<7>")
	)
	(segment
		(start 357.70058 -228.1809)
		(end 357.70058 -227.645214)
		(width 0.13208)
		(layer "F.Cu")
		(net "DMI_CPU0_PCH_RX_C_DP<6>")
	)
	(segment
		(start 357.70058 -227.645214)
		(end 357.700834 -227.64496)
		(width 0.13208)
		(layer "F.Cu")
		(net "DMI_CPU0_PCH_RX_C_DP<6>")
	)
	(segment
		(start 343.53754 -82.834988)
		(end 343.65946 -82.956908)
		(width 0.13208)
		(layer "B.Cu")
		(net "DMI_CPU0_PCH_RX_C_DP<6>")
	)
	(segment
		(start 343.65946 -82.956908)
		(end 343.65946 -85.509862)
		(width 0.13208)
		(layer "B.Cu")
		(net "DMI_CPU0_PCH_RX_C_DP<6>")
	)
	(segment
		(start 347.345 -60.116974)
		(end 347.345 -60.851288)
		(width 0.13208)
		(layer "B.Cu")
		(net "DMI_CPU0_PCH_RX_C_DP<6>")
	)
	(segment
		(start 349.359982 -69.551042)
		(end 350.081596 -70.630034)
		(width 0.13208)
		(layer "B.Cu")
		(net "DMI_CPU0_PCH_RX_C_DP<6>")
	)
	(segment
		(start 347.345 -60.851288)
		(end 347.5482 -61.342016)
		(width 0.13208)
		(layer "B.Cu")
		(net "DMI_CPU0_PCH_RX_C_DP<6>")
	)
	(segment
		(start 347.48724 -64.774318)
		(end 348.25813 -66.63563)
		(width 0.13208)
		(layer "B.Cu")
		(net "DMI_CPU0_PCH_RX_C_DP<6>")
	)
	(segment
		(start 343.65946 -81.647538)
		(end 343.65946 -82.332068)
		(width 0.13208)
		(layer "B.Cu")
		(net "DMI_CPU0_PCH_RX_C_DP<6>")
	)
	(segment
		(start 348.25813 -66.63563)
		(end 348.19082 -66.798444)
		(width 0.13208)
		(layer "B.Cu")
		(net "DMI_CPU0_PCH_RX_C_DP<6>")
	)
	(segment
		(start 345.982544 -59.218322)
		(end 346.446348 -59.218322)
		(width 0.13208)
		(layer "B.Cu")
		(net "DMI_CPU0_PCH_RX_C_DP<6>")
	)
	(segment
		(start 343.53754 -82.453988)
		(end 343.53754 -82.834988)
		(width 0.13208)
		(layer "B.Cu")
		(net "DMI_CPU0_PCH_RX_C_DP<6>")
	)
	(segment
		(start 348.83852 -68.292218)
		(end 349.359982 -69.551042)
		(width 0.13208)
		(layer "B.Cu")
		(net "DMI_CPU0_PCH_RX_C_DP<6>")
	)
	(segment
		(start 348.336616 -67.150488)
		(end 348.49943 -67.218052)
		(width 0.13208)
		(layer "B.Cu")
		(net "DMI_CPU0_PCH_RX_C_DP<6>")
	)
	(segment
		(start 343.65946 -82.332068)
		(end 343.53754 -82.453988)
		(width 0.13208)
		(layer "B.Cu")
		(net "DMI_CPU0_PCH_RX_C_DP<6>")
	)
	(segment
		(start 348.49943 -67.218052)
		(end 348.83852 -68.03644)
		(width 0.13208)
		(layer "B.Cu")
		(net "DMI_CPU0_PCH_RX_C_DP<6>")
	)
	(segment
		(start 346.446348 -59.218322)
		(end 347.345 -60.116974)
		(width 0.13208)
		(layer "B.Cu")
		(net "DMI_CPU0_PCH_RX_C_DP<6>")
	)
	(segment
		(start 348.83852 -68.03644)
		(end 348.83852 -68.292218)
		(width 0.13208)
		(layer "B.Cu")
		(net "DMI_CPU0_PCH_RX_C_DP<6>")
	)
	(segment
		(start 347.48724 -62.831218)
		(end 347.48724 -64.774318)
		(width 0.13208)
		(layer "B.Cu")
		(net "DMI_CPU0_PCH_RX_C_DP<6>")
	)
	(segment
		(start 347.5482 -61.342016)
		(end 347.5482 -62.684152)
		(width 0.13208)
		(layer "B.Cu")
		(net "DMI_CPU0_PCH_RX_C_DP<6>")
	)
	(segment
		(start 347.5482 -62.684152)
		(end 347.48724 -62.831218)
		(width 0.13208)
		(layer "B.Cu")
		(net "DMI_CPU0_PCH_RX_C_DP<6>")
	)
	(segment
		(start 343.65946 -85.509862)
		(end 343.3572 -85.812122)
		(width 0.13208)
		(layer "B.Cu")
		(net "DMI_CPU0_PCH_RX_C_DP<6>")
	)
	(segment
		(start 350.081596 -70.630034)
		(end 350.081596 -75.225402)
		(width 0.13208)
		(layer "B.Cu")
		(net "DMI_CPU0_PCH_RX_C_DP<6>")
	)
	(segment
		(start 348.19082 -66.798444)
		(end 348.336616 -67.150488)
		(width 0.13208)
		(layer "B.Cu")
		(net "DMI_CPU0_PCH_RX_C_DP<6>")
	)
	(segment
		(start 350.081596 -75.225402)
		(end 343.65946 -81.647538)
		(width 0.13208)
		(layer "B.Cu")
		(net "DMI_CPU0_PCH_RX_C_DP<6>")
	)
	(segment
		(start 343.65184 -86.622128)
		(end 343.65184 -86.106762)
		(width 0.14732)
		(layer "In6.Cu")
		(net "DMI_CPU0_PCH_RX_C_DP<6>")
	)
	(segment
		(start 359.015284 -224.404936)
		(end 359.015284 -224.373948)
		(width 0.0889)
		(layer "In6.Cu")
		(net "DMI_CPU0_PCH_RX_C_DP<6>")
	)
	(segment
		(start 364.466632 -218.202764)
		(end 364.468156 -218.202002)
		(width 0.0889)
		(layer "In6.Cu")
		(net "DMI_CPU0_PCH_RX_C_DP<6>")
	)
	(segment
		(start 366.097312 -213.088728)
		(end 366.097312 -212.824568)
		(width 0.0889)
		(layer "In6.Cu")
		(net "DMI_CPU0_PCH_RX_C_DP<6>")
	)
	(segment
		(start 365.998252 -213.187788)
		(end 366.097312 -213.088728)
		(width 0.0889)
		(layer "In6.Cu")
		(net "DMI_CPU0_PCH_RX_C_DP<6>")
	)
	(segment
		(start 358.821736 -226.345242)
		(end 358.836722 -226.336352)
		(width 0.0889)
		(layer "In6.Cu")
		(net "DMI_CPU0_PCH_RX_C_DP<6>")
	)
	(segment
		(start 363.523022 -219.832682)
		(end 363.526832 -219.830396)
		(width 0.0889)
		(layer "In6.Cu")
		(net "DMI_CPU0_PCH_RX_C_DP<6>")
	)
	(segment
		(start 359.306368 -224.88398)
		(end 359.298494 -224.879408)
		(width 0.0889)
		(layer "In6.Cu")
		(net "DMI_CPU0_PCH_RX_C_DP<6>")
	)
	(segment
		(start 363.24413 -220.327474)
		(end 363.24413 -220.319854)
		(width 0.0889)
		(layer "In6.Cu")
		(net "DMI_CPU0_PCH_RX_C_DP<6>")
	)
	(segment
		(start 358.54513 -226.83978)
		(end 358.54513 -226.831144)
		(width 0.0889)
		(layer "In6.Cu")
		(net "DMI_CPU0_PCH_RX_C_DP<6>")
	)
	(segment
		(start 357.700834 -227.64496)
		(end 357.857298 -227.915978)
		(width 0.0889)
		(layer "In6.Cu")
		(net "DMI_CPU0_PCH_RX_C_DP<6>")
	)
	(segment
		(start 361.732322 -222.266002)
		(end 361.742736 -222.272098)
		(width 0.0889)
		(layer "In6.Cu")
		(net "DMI_CPU0_PCH_RX_C_DP<6>")
	)
	(segment
		(start 364.468156 -218.202002)
		(end 364.475522 -218.197684)
		(width 0.0889)
		(layer "In6.Cu")
		(net "DMI_CPU0_PCH_RX_C_DP<6>")
	)
	(segment
		(start 363.528356 -221.45752)
		(end 363.535722 -221.453202)
		(width 0.0889)
		(layer "In6.Cu")
		(net "DMI_CPU0_PCH_RX_C_DP<6>")
	)
	(segment
		(start 372.142004 -198.162164)
		(end 375.590308 -195.74764)
		(width 0.14732)
		(layer "In6.Cu")
		(net "DMI_CPU0_PCH_RX_C_DP<6>")
	)
	(segment
		(start 366.097312 -212.824568)
		(end 365.998252 -212.725508)
		(width 0.0889)
		(layer "In6.Cu")
		(net "DMI_CPU0_PCH_RX_C_DP<6>")
	)
	(segment
		(start 364.46587 -218.203272)
		(end 364.466632 -218.202764)
		(width 0.0889)
		(layer "In6.Cu")
		(net "DMI_CPU0_PCH_RX_C_DP<6>")
	)
	(segment
		(start 362.304584 -221.94774)
		(end 362.304584 -221.937834)
		(width 0.0889)
		(layer "In6.Cu")
		(net "DMI_CPU0_PCH_RX_C_DP<6>")
	)
	(segment
		(start 379.785118 -154.09799)
		(end 343.916 -87.66683)
		(width 0.14732)
		(layer "In6.Cu")
		(net "DMI_CPU0_PCH_RX_C_DP<6>")
	)
	(segment
		(start 359.298494 -223.899476)
		(end 359.306368 -223.894904)
		(width 0.0889)
		(layer "In6.Cu")
		(net "DMI_CPU0_PCH_RX_C_DP<6>")
	)
	(segment
		(start 363.526832 -219.830396)
		(end 363.535722 -219.825316)
		(width 0.0889)
		(layer "In6.Cu")
		(net "DMI_CPU0_PCH_RX_C_DP<6>")
	)
	(segment
		(start 358.075484 -227.64496)
		(end 358.075484 -227.635054)
		(width 0.0889)
		(layer "In6.Cu")
		(net "DMI_CPU0_PCH_RX_C_DP<6>")
	)
	(segment
		(start 359.767632 -223.085914)
		(end 359.776522 -223.080834)
		(width 0.0889)
		(layer "In6.Cu")
		(net "DMI_CPU0_PCH_RX_C_DP<6>")
	)
	(segment
		(start 362.117132 -222.272098)
		(end 362.126022 -222.267018)
		(width 0.0889)
		(layer "In6.Cu")
		(net "DMI_CPU0_PCH_RX_C_DP<6>")
	)
	(segment
		(start 365.483648 -214.88781)
		(end 366.097312 -214.273892)
		(width 0.0889)
		(layer "In6.Cu")
		(net "DMI_CPU0_PCH_RX_C_DP<6>")
	)
	(segment
		(start 363.51464 -219.837508)
		(end 363.523022 -219.832682)
		(width 0.0889)
		(layer "In6.Cu")
		(net "DMI_CPU0_PCH_RX_C_DP<6>")
	)
	(segment
		(start 366.343438 -206.443326)
		(end 372.142004 -198.162164)
		(width 0.14732)
		(layer "In6.Cu")
		(net "DMI_CPU0_PCH_RX_C_DP<6>")
	)
	(segment
		(start 366.055148 -211.59089)
		(end 366.055148 -208.079594)
		(width 0.14732)
		(layer "In6.Cu")
		(net "DMI_CPU0_PCH_RX_C_DP<6>")
	)
	(segment
		(start 359.297478 -225.527616)
		(end 359.306368 -225.522536)
		(width 0.0889)
		(layer "In6.Cu")
		(net "DMI_CPU0_PCH_RX_C_DP<6>")
	)
	(segment
		(start 364.460536 -216.578434)
		(end 364.475522 -216.569544)
		(width 0.0889)
		(layer "In6.Cu")
		(net "DMI_CPU0_PCH_RX_C_DP<6>")
	)
	(segment
		(start 366.097312 -212.362288)
		(end 366.097312 -211.655152)
		(width 0.0889)
		(layer "In6.Cu")
		(net "DMI_CPU0_PCH_RX_C_DP<6>")
	)
	(segment
		(start 365.998252 -213.451948)
		(end 365.998252 -213.187788)
		(width 0.0889)
		(layer "In6.Cu")
		(net "DMI_CPU0_PCH_RX_C_DP<6>")
	)
	(segment
		(start 359.298494 -224.879408)
		(end 359.297478 -224.8789)
		(width 0.0889)
		(layer "In6.Cu")
		(net "DMI_CPU0_PCH_RX_C_DP<6>")
	)
	(segment
		(start 364.18393 -217.07856)
		(end 364.18393 -217.064336)
		(width 0.0889)
		(layer "In6.Cu")
		(net "DMI_CPU0_PCH_RX_C_DP<6>")
	)
	(segment
		(start 366.097312 -213.551008)
		(end 365.998252 -213.451948)
		(width 0.0889)
		(layer "In6.Cu")
		(net "DMI_CPU0_PCH_RX_C_DP<6>")
	)
	(segment
		(start 366.097312 -211.655152)
		(end 366.055148 -211.612988)
		(width 0.0889)
		(layer "In6.Cu")
		(net "DMI_CPU0_PCH_RX_C_DP<6>")
	)
	(segment
		(start 364.475522 -217.559128)
		(end 364.466632 -217.554048)
		(width 0.0889)
		(layer "In6.Cu")
		(net "DMI_CPU0_PCH_RX_C_DP<6>")
	)
	(segment
		(start 366.055148 -211.612988)
		(end 366.055148 -211.59089)
		(width 0.0889)
		(layer "In6.Cu")
		(net "DMI_CPU0_PCH_RX_C_DP<6>")
	)
	(segment
		(start 383.750312 -176.58207)
		(end 379.785118 -154.09799)
		(width 0.14732)
		(layer "In6.Cu")
		(net "DMI_CPU0_PCH_RX_C_DP<6>")
	)
	(segment
		(start 375.590308 -195.74764)
		(end 381.97917 -186.622944)
		(width 0.14732)
		(layer "In6.Cu")
		(net "DMI_CPU0_PCH_RX_C_DP<6>")
	)
	(segment
		(start 364.936278 -215.761062)
		(end 364.945168 -215.755982)
		(width 0.0889)
		(layer "In6.Cu")
		(net "DMI_CPU0_PCH_RX_C_DP<6>")
	)
	(segment
		(start 364.654084 -216.25052)
		(end 364.654084 -216.235026)
		(width 0.0889)
		(layer "In6.Cu")
		(net "DMI_CPU0_PCH_RX_C_DP<6>")
	)
	(segment
		(start 366.055148 -208.079594)
		(end 366.343438 -206.443326)
		(width 0.14732)
		(layer "In6.Cu")
		(net "DMI_CPU0_PCH_RX_C_DP<6>")
	)
	(segment
		(start 359.015284 -226.017328)
		(end 359.015284 -225.99523)
		(width 0.0889)
		(layer "In6.Cu")
		(net "DMI_CPU0_PCH_RX_C_DP<6>")
	)
	(segment
		(start 357.857298 -227.915978)
		(end 357.93553 -227.936806)
		(width 0.0889)
		(layer "In6.Cu")
		(net "DMI_CPU0_PCH_RX_C_DP<6>")
	)
	(segment
		(start 363.535722 -220.814646)
		(end 363.526832 -220.809566)
		(width 0.0889)
		(layer "In6.Cu")
		(net "DMI_CPU0_PCH_RX_C_DP<6>")
	)
	(segment
		(start 358.836722 -226.336352)
		(end 358.836722 -226.336606)
		(width 0.0889)
		(layer "In6.Cu")
		(net "DMI_CPU0_PCH_RX_C_DP<6>")
	)
	(segment
		(start 365.483394 -214.88781)
		(end 365.483648 -214.88781)
		(width 0.0889)
		(layer "In6.Cu")
		(net "DMI_CPU0_PCH_RX_C_DP<6>")
	)
	(segment
		(start 359.955084 -222.761556)
		(end 359.955084 -222.746062)
		(width 0.0889)
		(layer "In6.Cu")
		(net "DMI_CPU0_PCH_RX_C_DP<6>")
	)
	(segment
		(start 359.297478 -223.899984)
		(end 359.298494 -223.899476)
		(width 0.0889)
		(layer "In6.Cu")
		(net "DMI_CPU0_PCH_RX_C_DP<6>")
	)
	(segment
		(start 365.998252 -212.461348)
		(end 366.097312 -212.362288)
		(width 0.0889)
		(layer "In6.Cu")
		(net "DMI_CPU0_PCH_RX_C_DP<6>")
	)
	(segment
		(start 363.714284 -219.506038)
		(end 363.714284 -219.490544)
		(width 0.0889)
		(layer "In6.Cu")
		(net "DMI_CPU0_PCH_RX_C_DP<6>")
	)
	(segment
		(start 363.526832 -221.458282)
		(end 363.528356 -221.45752)
		(width 0.0889)
		(layer "In6.Cu")
		(net "DMI_CPU0_PCH_RX_C_DP<6>")
	)
	(segment
		(start 364.475522 -216.569544)
		(end 364.475522 -216.569798)
		(width 0.0889)
		(layer "In6.Cu")
		(net "DMI_CPU0_PCH_RX_C_DP<6>")
	)
	(segment
		(start 343.65184 -86.106762)
		(end 343.3572 -85.812122)
		(width 0.14732)
		(layer "In6.Cu")
		(net "DMI_CPU0_PCH_RX_C_DP<6>")
	)
	(segment
		(start 365.998252 -212.725508)
		(end 365.998252 -212.461348)
		(width 0.0889)
		(layer "In6.Cu")
		(net "DMI_CPU0_PCH_RX_C_DP<6>")
	)
	(segment
		(start 381.97917 -186.622944)
		(end 383.750312 -176.58207)
		(width 0.14732)
		(layer "In6.Cu")
		(net "DMI_CPU0_PCH_RX_C_DP<6>")
	)
	(segment
		(start 363.996478 -219.01658)
		(end 364.005368 -219.0115)
		(width 0.0889)
		(layer "In6.Cu")
		(net "DMI_CPU0_PCH_RX_C_DP<6>")
	)
	(segment
		(start 359.48493 -223.575626)
		(end 359.48493 -223.568006)
		(width 0.0889)
		(layer "In6.Cu")
		(net "DMI_CPU0_PCH_RX_C_DP<6>")
	)
	(segment
		(start 366.097312 -214.273892)
		(end 366.097312 -213.551008)
		(width 0.0889)
		(layer "In6.Cu")
		(net "DMI_CPU0_PCH_RX_C_DP<6>")
	)
	(segment
		(start 365.12373 -215.436704)
		(end 365.12373 -215.42121)
		(width 0.0889)
		(layer "In6.Cu")
		(net "DMI_CPU0_PCH_RX_C_DP<6>")
	)
	(segment
		(start 343.916 -87.66683)
		(end 343.65184 -86.622128)
		(width 0.14732)
		(layer "In6.Cu")
		(net "DMI_CPU0_PCH_RX_C_DP<6>")
	)
	(segment
		(start 360.78795 -222.263462)
		(end 360.802682 -222.272098)
		(width 0.0889)
		(layer "In6.Cu")
		(net "DMI_CPU0_PCH_RX_C_DP<6>")
	)
	(segment
		(start 364.460536 -218.20632)
		(end 364.46587 -218.203272)
		(width 0.0889)
		(layer "In6.Cu")
		(net "DMI_CPU0_PCH_RX_C_DP<6>")
	)
	(arc
		(start 364.475522 -218.197684)
		(mid 364.65424 -217.878406)
		(end 364.475522 -217.559128)
		(width 0.0889)
		(layer "In6.Cu")
		(net "DMI_CPU0_PCH_RX_C_DP<6>")
	)
	(arc
		(start 364.654084 -216.235026)
		(mid 364.733454 -215.961292)
		(end 364.936278 -215.761062)
		(width 0.0889)
		(layer "In6.Cu")
		(net "DMI_CPU0_PCH_RX_C_DP<6>")
	)
	(arc
		(start 358.54513 -226.831144)
		(mid 358.619121 -226.551578)
		(end 358.821736 -226.345242)
		(width 0.0889)
		(layer "In6.Cu")
		(net "DMI_CPU0_PCH_RX_C_DP<6>")
	)
	(arc
		(start 364.475522 -216.569798)
		(mid 364.606436 -216.433438)
		(end 364.654084 -216.25052)
		(width 0.0889)
		(layer "In6.Cu")
		(net "DMI_CPU0_PCH_RX_C_DP<6>")
	)
	(arc
		(start 364.18393 -218.692222)
		(mid 364.257921 -218.412656)
		(end 364.460536 -218.20632)
		(width 0.0889)
		(layer "In6.Cu")
		(net "DMI_CPU0_PCH_RX_C_DP<6>")
	)
	(arc
		(start 363.714284 -219.490544)
		(mid 363.793654 -219.21681)
		(end 363.996478 -219.01658)
		(width 0.0889)
		(layer "In6.Cu")
		(net "DMI_CPU0_PCH_RX_C_DP<6>")
	)
	(arc
		(start 363.535722 -221.453202)
		(mid 363.714198 -221.133924)
		(end 363.535722 -220.814646)
		(width 0.0889)
		(layer "In6.Cu")
		(net "DMI_CPU0_PCH_RX_C_DP<6>")
	)
	(arc
		(start 359.015284 -224.373948)
		(mid 359.094654 -224.100214)
		(end 359.297478 -223.899984)
		(width 0.0889)
		(layer "In6.Cu")
		(net "DMI_CPU0_PCH_RX_C_DP<6>")
	)
	(arc
		(start 363.535722 -219.825316)
		(mid 363.666636 -219.688956)
		(end 363.714284 -219.506038)
		(width 0.0889)
		(layer "In6.Cu")
		(net "DMI_CPU0_PCH_RX_C_DP<6>")
	)
	(arc
		(start 359.955084 -222.746062)
		(mid 360.034454 -222.472328)
		(end 360.237278 -222.272098)
		(width 0.0889)
		(layer "In6.Cu")
		(net "DMI_CPU0_PCH_RX_C_DP<6>")
	)
	(arc
		(start 363.526832 -220.809566)
		(mid 363.32176 -220.605887)
		(end 363.24413 -220.327474)
		(width 0.0889)
		(layer "In6.Cu")
		(net "DMI_CPU0_PCH_RX_C_DP<6>")
	)
	(arc
		(start 363.24413 -220.319854)
		(mid 363.316365 -220.04333)
		(end 363.51464 -219.837508)
		(width 0.0889)
		(layer "In6.Cu")
		(net "DMI_CPU0_PCH_RX_C_DP<6>")
	)
	(arc
		(start 359.776522 -223.080834)
		(mid 359.907436 -222.944474)
		(end 359.955084 -222.761556)
		(width 0.0889)
		(layer "In6.Cu")
		(net "DMI_CPU0_PCH_RX_C_DP<6>")
	)
	(arc
		(start 360.802682 -222.272098)
		(mid 360.98988 -222.322241)
		(end 361.177078 -222.272098)
		(width 0.0889)
		(layer "In6.Cu")
		(net "DMI_CPU0_PCH_RX_C_DP<6>")
	)
	(arc
		(start 358.836722 -226.336606)
		(mid 358.967636 -226.200246)
		(end 359.015284 -226.017328)
		(width 0.0889)
		(layer "In6.Cu")
		(net "DMI_CPU0_PCH_RX_C_DP<6>")
	)
	(arc
		(start 360.237278 -222.272098)
		(mid 360.511477 -222.196263)
		(end 360.78795 -222.263462)
		(width 0.0889)
		(layer "In6.Cu")
		(net "DMI_CPU0_PCH_RX_C_DP<6>")
	)
	(arc
		(start 358.075484 -227.635054)
		(mid 358.153595 -227.358105)
		(end 358.357932 -227.155502)
		(width 0.0889)
		(layer "In6.Cu")
		(net "DMI_CPU0_PCH_RX_C_DP<6>")
	)
	(arc
		(start 359.484676 -225.21799)
		(mid 359.484873 -225.210625)
		(end 359.48493 -225.203258)
		(width 0.0889)
		(layer "In6.Cu")
		(net "DMI_CPU0_PCH_RX_C_DP<6>")
	)
	(arc
		(start 364.18393 -217.064336)
		(mid 364.257921 -216.78477)
		(end 364.460536 -216.578434)
		(width 0.0889)
		(layer "In6.Cu")
		(net "DMI_CPU0_PCH_RX_C_DP<6>")
	)
	(arc
		(start 361.742736 -222.272098)
		(mid 361.929934 -222.322241)
		(end 362.117132 -222.272098)
		(width 0.0889)
		(layer "In6.Cu")
		(net "DMI_CPU0_PCH_RX_C_DP<6>")
	)
	(arc
		(start 359.48493 -223.568006)
		(mid 359.562559 -223.289593)
		(end 359.767632 -223.085914)
		(width 0.0889)
		(layer "In6.Cu")
		(net "DMI_CPU0_PCH_RX_C_DP<6>")
	)
	(arc
		(start 362.304584 -221.937834)
		(mid 362.382695 -221.660885)
		(end 362.587032 -221.458282)
		(width 0.0889)
		(layer "In6.Cu")
		(net "DMI_CPU0_PCH_RX_C_DP<6>")
	)
	(arc
		(start 359.306368 -223.894904)
		(mid 359.437282 -223.758544)
		(end 359.48493 -223.575626)
		(width 0.0889)
		(layer "In6.Cu")
		(net "DMI_CPU0_PCH_RX_C_DP<6>")
	)
	(arc
		(start 359.015284 -225.99523)
		(mid 359.096195 -225.725102)
		(end 359.297478 -225.527616)
		(width 0.0889)
		(layer "In6.Cu")
		(net "DMI_CPU0_PCH_RX_C_DP<6>")
	)
	(arc
		(start 364.005368 -219.0115)
		(mid 364.136282 -218.87514)
		(end 364.18393 -218.692222)
		(width 0.0889)
		(layer "In6.Cu")
		(net "DMI_CPU0_PCH_RX_C_DP<6>")
	)
	(arc
		(start 359.297478 -224.8789)
		(mid 359.094655 -224.678669)
		(end 359.015284 -224.404936)
		(width 0.0889)
		(layer "In6.Cu")
		(net "DMI_CPU0_PCH_RX_C_DP<6>")
	)
	(arc
		(start 363.152436 -221.458282)
		(mid 363.339634 -221.508425)
		(end 363.526832 -221.458282)
		(width 0.0889)
		(layer "In6.Cu")
		(net "DMI_CPU0_PCH_RX_C_DP<6>")
	)
	(arc
		(start 364.945168 -215.755982)
		(mid 365.076082 -215.619622)
		(end 365.12373 -215.436704)
		(width 0.0889)
		(layer "In6.Cu")
		(net "DMI_CPU0_PCH_RX_C_DP<6>")
	)
	(arc
		(start 357.93553 -227.936806)
		(mid 358.038675 -227.806781)
		(end 358.075484 -227.64496)
		(width 0.0889)
		(layer "In6.Cu")
		(net "DMI_CPU0_PCH_RX_C_DP<6>")
	)
	(arc
		(start 362.126022 -222.267018)
		(mid 362.256936 -222.130658)
		(end 362.304584 -221.94774)
		(width 0.0889)
		(layer "In6.Cu")
		(net "DMI_CPU0_PCH_RX_C_DP<6>")
	)
	(arc
		(start 365.12373 -215.42121)
		(mid 365.2031 -215.147476)
		(end 365.405924 -214.947246)
		(width 0.0889)
		(layer "In6.Cu")
		(net "DMI_CPU0_PCH_RX_C_DP<6>")
	)
	(arc
		(start 359.48493 -225.203258)
		(mid 359.437251 -225.020358)
		(end 359.306368 -224.88398)
		(width 0.0889)
		(layer "In6.Cu")
		(net "DMI_CPU0_PCH_RX_C_DP<6>")
	)
	(arc
		(start 364.466632 -217.554048)
		(mid 364.263151 -217.353244)
		(end 364.18393 -217.07856)
		(width 0.0889)
		(layer "In6.Cu")
		(net "DMI_CPU0_PCH_RX_C_DP<6>")
	)
	(arc
		(start 365.405924 -214.947246)
		(mid 365.446594 -214.920052)
		(end 365.483394 -214.88781)
		(width 0.0889)
		(layer "In6.Cu")
		(net "DMI_CPU0_PCH_RX_C_DP<6>")
	)
	(arc
		(start 362.587032 -221.458282)
		(mid 362.869734 -221.382506)
		(end 363.152436 -221.458282)
		(width 0.0889)
		(layer "In6.Cu")
		(net "DMI_CPU0_PCH_RX_C_DP<6>")
	)
	(arc
		(start 361.177078 -222.272098)
		(mid 361.453891 -222.196228)
		(end 361.732322 -222.266002)
		(width 0.0889)
		(layer "In6.Cu")
		(net "DMI_CPU0_PCH_RX_C_DP<6>")
	)
	(arc
		(start 359.306368 -225.522536)
		(mid 359.433622 -225.39257)
		(end 359.484676 -225.21799)
		(width 0.0889)
		(layer "In6.Cu")
		(net "DMI_CPU0_PCH_RX_C_DP<6>")
	)
	(arc
		(start 358.357932 -227.155502)
		(mid 358.492865 -227.022148)
		(end 358.54513 -226.83978)
		(width 0.0889)
		(layer "In6.Cu")
		(net "DMI_CPU0_PCH_RX_C_DP<6>")
	)
	(segment
		(start 357.230934 -227.367084)
		(end 357.23068 -227.36683)
		(width 0.13208)
		(layer "F.Cu")
		(net "DMI_CPU0_PCH_RX_C_DP<5>")
	)
	(segment
		(start 357.23068 -227.36683)
		(end 357.23068 -226.831144)
		(width 0.13208)
		(layer "F.Cu")
		(net "DMI_CPU0_PCH_RX_C_DP<5>")
	)
	(segment
		(start 345.877642 -65.682622)
		(end 345.877642 -64.678306)
		(width 0.13208)
		(layer "B.Cu")
		(net "DMI_CPU0_PCH_RX_C_DP<5>")
	)
	(segment
		(start 341.737696 -83.561174)
		(end 342.039956 -83.258914)
		(width 0.13208)
		(layer "B.Cu")
		(net "DMI_CPU0_PCH_RX_C_DP<5>")
	)
	(segment
		(start 345.877642 -64.678306)
		(end 345.5543 -64.354964)
		(width 0.13208)
		(layer "B.Cu")
		(net "DMI_CPU0_PCH_RX_C_DP<5>")
	)
	(segment
		(start 342.039956 -81.45272)
		(end 348.798896 -74.69378)
		(width 0.13208)
		(layer "B.Cu")
		(net "DMI_CPU0_PCH_RX_C_DP<5>")
	)
	(segment
		(start 348.798896 -74.69378)
		(end 348.798896 -70.92315)
		(width 0.13208)
		(layer "B.Cu")
		(net "DMI_CPU0_PCH_RX_C_DP<5>")
	)
	(segment
		(start 346.359988 -67.272662)
		(end 345.877642 -65.682622)
		(width 0.13208)
		(layer "B.Cu")
		(net "DMI_CPU0_PCH_RX_C_DP<5>")
	)
	(segment
		(start 348.798896 -70.92315)
		(end 346.359988 -67.272662)
		(width 0.13208)
		(layer "B.Cu")
		(net "DMI_CPU0_PCH_RX_C_DP<5>")
	)
	(segment
		(start 342.039956 -83.258914)
		(end 342.039956 -81.45272)
		(width 0.13208)
		(layer "B.Cu")
		(net "DMI_CPU0_PCH_RX_C_DP<5>")
	)
	(segment
		(start 342.032336 -83.855814)
		(end 341.737696 -83.561174)
		(width 0.14732)
		(layer "In6.Cu")
		(net "DMI_CPU0_PCH_RX_C_DP<5>")
	)
	(segment
		(start 358.075484 -226.017328)
		(end 358.075484 -225.99523)
		(width 0.0889)
		(layer "In6.Cu")
		(net "DMI_CPU0_PCH_RX_C_DP<5>")
	)
	(segment
		(start 341.897716 -85.090508)
		(end 341.897716 -84.729828)
		(width 0.14732)
		(layer "In6.Cu")
		(net "DMI_CPU0_PCH_RX_C_DP<5>")
	)
	(segment
		(start 365.00562 -212.884512)
		(end 365.00562 -212.620352)
		(width 0.0889)
		(layer "In6.Cu")
		(net "DMI_CPU0_PCH_RX_C_DP<5>")
	)
	(segment
		(start 365.00562 -212.158072)
		(end 365.00562 -211.893912)
		(width 0.0889)
		(layer "In6.Cu")
		(net "DMI_CPU0_PCH_RX_C_DP<5>")
	)
	(segment
		(start 364.184184 -215.368632)
		(end 364.184438 -215.368124)
		(width 0.0889)
		(layer "In6.Cu")
		(net "DMI_CPU0_PCH_RX_C_DP<5>")
	)
	(segment
		(start 365.10468 -213.710012)
		(end 365.00562 -213.610952)
		(width 0.0889)
		(layer "In6.Cu")
		(net "DMI_CPU0_PCH_RX_C_DP<5>")
	)
	(segment
		(start 382.821688 -176.889156)
		(end 382.697482 -176.327562)
		(width 0.14732)
		(layer "In6.Cu")
		(net "DMI_CPU0_PCH_RX_C_DP<5>")
	)
	(segment
		(start 363.535722 -217.559128)
		(end 363.526832 -217.554048)
		(width 0.0889)
		(layer "In6.Cu")
		(net "DMI_CPU0_PCH_RX_C_DP<5>")
	)
	(segment
		(start 342.032336 -84.595208)
		(end 342.032336 -83.855814)
		(width 0.14732)
		(layer "In6.Cu")
		(net "DMI_CPU0_PCH_RX_C_DP<5>")
	)
	(segment
		(start 363.528356 -218.202002)
		(end 363.535722 -218.197684)
		(width 0.0889)
		(layer "In6.Cu")
		(net "DMI_CPU0_PCH_RX_C_DP<5>")
	)
	(segment
		(start 362.588556 -219.829634)
		(end 362.595922 -219.825316)
		(width 0.0889)
		(layer "In6.Cu")
		(net "DMI_CPU0_PCH_RX_C_DP<5>")
	)
	(segment
		(start 365.10468 -212.521292)
		(end 365.10468 -212.257132)
		(width 0.0889)
		(layer "In6.Cu")
		(net "DMI_CPU0_PCH_RX_C_DP<5>")
	)
	(segment
		(start 359.015284 -222.761556)
		(end 359.015284 -222.75165)
		(width 0.0889)
		(layer "In6.Cu")
		(net "DMI_CPU0_PCH_RX_C_DP<5>")
	)
	(segment
		(start 357.23068 -226.831144)
		(end 357.074216 -227.102162)
		(width 0.0889)
		(layer "In6.Cu")
		(net "DMI_CPU0_PCH_RX_C_DP<5>")
	)
	(segment
		(start 365.10468 -214.274146)
		(end 365.10468 -213.710012)
		(width 0.0889)
		(layer "In6.Cu")
		(net "DMI_CPU0_PCH_RX_C_DP<5>")
	)
	(segment
		(start 365.062516 -210.983068)
		(end 365.062516 -208.30413)
		(width 0.14732)
		(layer "In6.Cu")
		(net "DMI_CPU0_PCH_RX_C_DP<5>")
	)
	(segment
		(start 365.00562 -211.893912)
		(end 365.10468 -211.794852)
		(width 0.0889)
		(layer "In6.Cu")
		(net "DMI_CPU0_PCH_RX_C_DP<5>")
	)
	(segment
		(start 358.366568 -224.88398)
		(end 358.357678 -224.8789)
		(width 0.0889)
		(layer "In6.Cu")
		(net "DMI_CPU0_PCH_RX_C_DP<5>")
	)
	(segment
		(start 342.504522 -88.34247)
		(end 342.032336 -86.500462)
		(width 0.14732)
		(layer "In6.Cu")
		(net "DMI_CPU0_PCH_RX_C_DP<5>")
	)
	(segment
		(start 365.00562 -213.346792)
		(end 365.10468 -213.247732)
		(width 0.0889)
		(layer "In6.Cu")
		(net "DMI_CPU0_PCH_RX_C_DP<5>")
	)
	(segment
		(start 365.10468 -212.257132)
		(end 365.00562 -212.158072)
		(width 0.0889)
		(layer "In6.Cu")
		(net "DMI_CPU0_PCH_RX_C_DP<5>")
	)
	(segment
		(start 359.48493 -221.956376)
		(end 359.48493 -221.94774)
		(width 0.0889)
		(layer "In6.Cu")
		(net "DMI_CPU0_PCH_RX_C_DP<5>")
	)
	(segment
		(start 357.886762 -226.342448)
		(end 357.888032 -226.341686)
		(width 0.0889)
		(layer "In6.Cu")
		(net "DMI_CPU0_PCH_RX_C_DP<5>")
	)
	(segment
		(start 357.888032 -226.341686)
		(end 357.896922 -226.336606)
		(width 0.0889)
		(layer "In6.Cu")
		(net "DMI_CPU0_PCH_RX_C_DP<5>")
	)
	(segment
		(start 371.26799 -197.67931)
		(end 374.909334 -195.129658)
		(width 0.14732)
		(layer "In6.Cu")
		(net "DMI_CPU0_PCH_RX_C_DP<5>")
	)
	(segment
		(start 342.032336 -85.225128)
		(end 341.897716 -85.090508)
		(width 0.14732)
		(layer "In6.Cu")
		(net "DMI_CPU0_PCH_RX_C_DP<5>")
	)
	(segment
		(start 341.897716 -84.729828)
		(end 342.032336 -84.595208)
		(width 0.14732)
		(layer "In6.Cu")
		(net "DMI_CPU0_PCH_RX_C_DP<5>")
	)
	(segment
		(start 359.769156 -221.45752)
		(end 359.776522 -221.453202)
		(width 0.0889)
		(layer "In6.Cu")
		(net "DMI_CPU0_PCH_RX_C_DP<5>")
	)
	(segment
		(start 363.980984 -215.77046)
		(end 363.996986 -215.761062)
		(width 0.0889)
		(layer "In6.Cu")
		(net "DMI_CPU0_PCH_RX_C_DP<5>")
	)
	(segment
		(start 362.774484 -219.506038)
		(end 362.774484 -219.496132)
		(width 0.0889)
		(layer "In6.Cu")
		(net "DMI_CPU0_PCH_RX_C_DP<5>")
	)
	(segment
		(start 365.00562 -213.610952)
		(end 365.00562 -213.346792)
		(width 0.0889)
		(layer "In6.Cu")
		(net "DMI_CPU0_PCH_RX_C_DP<5>")
	)
	(segment
		(start 378.866654 -154.607768)
		(end 342.504522 -88.34247)
		(width 0.14732)
		(layer "In6.Cu")
		(net "DMI_CPU0_PCH_RX_C_DP<5>")
	)
	(segment
		(start 362.587032 -219.830396)
		(end 362.588556 -219.829634)
		(width 0.0889)
		(layer "In6.Cu")
		(net "DMI_CPU0_PCH_RX_C_DP<5>")
	)
	(segment
		(start 363.24413 -218.700858)
		(end 363.24413 -218.692222)
		(width 0.0889)
		(layer "In6.Cu")
		(net "DMI_CPU0_PCH_RX_C_DP<5>")
	)
	(segment
		(start 364.30712 -215.071706)
		(end 365.10468 -214.274146)
		(width 0.0889)
		(layer "In6.Cu")
		(net "DMI_CPU0_PCH_RX_C_DP<5>")
	)
	(segment
		(start 365.10468 -211.794852)
		(end 365.10468 -211.04733)
		(width 0.0889)
		(layer "In6.Cu")
		(net "DMI_CPU0_PCH_RX_C_DP<5>")
	)
	(segment
		(start 358.827832 -223.085914)
		(end 358.836722 -223.080834)
		(width 0.0889)
		(layer "In6.Cu")
		(net "DMI_CPU0_PCH_RX_C_DP<5>")
	)
	(segment
		(start 365.00562 -212.620352)
		(end 365.10468 -212.521292)
		(width 0.0889)
		(layer "In6.Cu")
		(net "DMI_CPU0_PCH_RX_C_DP<5>")
	)
	(segment
		(start 358.54513 -223.584262)
		(end 358.54513 -223.561402)
		(width 0.0889)
		(layer "In6.Cu")
		(net "DMI_CPU0_PCH_RX_C_DP<5>")
	)
	(segment
		(start 342.032336 -86.500462)
		(end 342.032336 -85.225128)
		(width 0.14732)
		(layer "In6.Cu")
		(net "DMI_CPU0_PCH_RX_C_DP<5>")
	)
	(segment
		(start 382.697482 -176.327562)
		(end 378.866654 -154.607768)
		(width 0.14732)
		(layer "In6.Cu")
		(net "DMI_CPU0_PCH_RX_C_DP<5>")
	)
	(segment
		(start 361.656122 -220.814646)
		(end 361.647232 -220.809566)
		(width 0.0889)
		(layer "In6.Cu")
		(net "DMI_CPU0_PCH_RX_C_DP<5>")
	)
	(segment
		(start 365.062516 -211.005166)
		(end 365.062516 -210.983068)
		(width 0.0889)
		(layer "In6.Cu")
		(net "DMI_CPU0_PCH_RX_C_DP<5>")
	)
	(segment
		(start 364.184184 -215.44534)
		(end 364.184184 -215.368632)
		(width 0.0889)
		(layer "In6.Cu")
		(net "DMI_CPU0_PCH_RX_C_DP<5>")
	)
	(segment
		(start 365.10468 -211.04733)
		(end 365.062516 -211.005166)
		(width 0.0889)
		(layer "In6.Cu")
		(net "DMI_CPU0_PCH_RX_C_DP<5>")
	)
	(segment
		(start 361.085384 -221.1197)
		(end 361.085384 -221.133924)
		(width 0.0889)
		(layer "In6.Cu")
		(net "DMI_CPU0_PCH_RX_C_DP<5>")
	)
	(segment
		(start 381.18542 -186.165998)
		(end 382.821688 -176.889156)
		(width 0.14732)
		(layer "In6.Cu")
		(net "DMI_CPU0_PCH_RX_C_DP<5>")
	)
	(segment
		(start 365.477044 -205.948788)
		(end 371.26799 -197.67931)
		(width 0.14732)
		(layer "In6.Cu")
		(net "DMI_CPU0_PCH_RX_C_DP<5>")
	)
	(segment
		(start 357.074216 -227.102162)
		(end 357.095298 -227.18014)
		(width 0.0889)
		(layer "In6.Cu")
		(net "DMI_CPU0_PCH_RX_C_DP<5>")
	)
	(segment
		(start 359.955084 -221.133924)
		(end 359.955084 -221.115382)
		(width 0.0889)
		(layer "In6.Cu")
		(net "DMI_CPU0_PCH_RX_C_DP<5>")
	)
	(segment
		(start 363.520736 -218.20632)
		(end 363.528356 -218.202002)
		(width 0.0889)
		(layer "In6.Cu")
		(net "DMI_CPU0_PCH_RX_C_DP<5>")
	)
	(segment
		(start 357.885238 -226.34321)
		(end 357.886762 -226.342448)
		(width 0.0889)
		(layer "In6.Cu")
		(net "DMI_CPU0_PCH_RX_C_DP<5>")
	)
	(segment
		(start 365.10468 -213.247732)
		(end 365.10468 -212.983572)
		(width 0.0889)
		(layer "In6.Cu")
		(net "DMI_CPU0_PCH_RX_C_DP<5>")
	)
	(segment
		(start 374.909334 -195.129658)
		(end 381.18542 -186.165998)
		(width 0.14732)
		(layer "In6.Cu")
		(net "DMI_CPU0_PCH_RX_C_DP<5>")
	)
	(segment
		(start 359.761536 -221.461838)
		(end 359.769156 -221.45752)
		(width 0.0889)
		(layer "In6.Cu")
		(net "DMI_CPU0_PCH_RX_C_DP<5>")
	)
	(segment
		(start 365.10468 -212.983572)
		(end 365.00562 -212.884512)
		(width 0.0889)
		(layer "In6.Cu")
		(net "DMI_CPU0_PCH_RX_C_DP<5>")
	)
	(segment
		(start 357.87584 -226.348798)
		(end 357.885238 -226.34321)
		(width 0.0889)
		(layer "In6.Cu")
		(net "DMI_CPU0_PCH_RX_C_DP<5>")
	)
	(segment
		(start 363.520482 -216.578434)
		(end 363.535468 -216.569798)
		(width 0.0889)
		(layer "In6.Cu")
		(net "DMI_CPU0_PCH_RX_C_DP<5>")
	)
	(segment
		(start 358.357678 -225.527616)
		(end 358.366568 -225.522536)
		(width 0.0889)
		(layer "In6.Cu")
		(net "DMI_CPU0_PCH_RX_C_DP<5>")
	)
	(segment
		(start 365.062516 -208.30413)
		(end 365.477044 -205.948788)
		(width 0.14732)
		(layer "In6.Cu")
		(net "DMI_CPU0_PCH_RX_C_DP<5>")
	)
	(arc
		(start 363.24413 -218.692222)
		(mid 363.318121 -218.412656)
		(end 363.520736 -218.20632)
		(width 0.0889)
		(layer "In6.Cu")
		(net "DMI_CPU0_PCH_RX_C_DP<5>")
	)
	(arc
		(start 358.544876 -225.193098)
		(mid 358.494861 -225.015967)
		(end 358.366568 -224.88398)
		(width 0.0889)
		(layer "In6.Cu")
		(net "DMI_CPU0_PCH_RX_C_DP<5>")
	)
	(arc
		(start 361.085384 -221.133924)
		(mid 361.642934 -221.460895)
		(end 361.656122 -220.814646)
		(width 0.0889)
		(layer "In6.Cu")
		(net "DMI_CPU0_PCH_RX_C_DP<5>")
	)
	(arc
		(start 363.535468 -216.569798)
		(mid 363.666382 -216.433438)
		(end 363.71403 -216.25052)
		(width 0.0889)
		(layer "In6.Cu")
		(net "DMI_CPU0_PCH_RX_C_DP<5>")
	)
	(arc
		(start 358.366568 -225.522536)
		(mid 358.493648 -225.392522)
		(end 358.544622 -225.21799)
		(width 0.0889)
		(layer "In6.Cu")
		(net "DMI_CPU0_PCH_RX_C_DP<5>")
	)
	(arc
		(start 358.544622 -225.21799)
		(mid 358.544955 -225.205546)
		(end 358.544876 -225.193098)
		(width 0.0889)
		(layer "In6.Cu")
		(net "DMI_CPU0_PCH_RX_C_DP<5>")
	)
	(arc
		(start 363.056932 -219.01658)
		(mid 363.191865 -218.883226)
		(end 363.24413 -218.700858)
		(width 0.0889)
		(layer "In6.Cu")
		(net "DMI_CPU0_PCH_RX_C_DP<5>")
	)
	(arc
		(start 361.36453 -220.319854)
		(mid 361.647274 -219.830175)
		(end 362.212636 -219.830396)
		(width 0.0889)
		(layer "In6.Cu")
		(net "DMI_CPU0_PCH_RX_C_DP<5>")
	)
	(arc
		(start 359.955084 -221.115382)
		(mid 360.522392 -220.568474)
		(end 361.085384 -221.1197)
		(width 0.0889)
		(layer "In6.Cu")
		(net "DMI_CPU0_PCH_RX_C_DP<5>")
	)
	(arc
		(start 358.357678 -224.8789)
		(mid 358.075273 -224.389332)
		(end 358.357932 -223.899984)
		(width 0.0889)
		(layer "In6.Cu")
		(net "DMI_CPU0_PCH_RX_C_DP<5>")
	)
	(arc
		(start 357.095298 -227.18014)
		(mid 357.442369 -227.140159)
		(end 357.60533 -226.831144)
		(width 0.0889)
		(layer "In6.Cu")
		(net "DMI_CPU0_PCH_RX_C_DP<5>")
	)
	(arc
		(start 361.647232 -220.809566)
		(mid 361.440244 -220.602594)
		(end 361.36453 -220.319854)
		(width 0.0889)
		(layer "In6.Cu")
		(net "DMI_CPU0_PCH_RX_C_DP<5>")
	)
	(arc
		(start 359.015284 -222.75165)
		(mid 359.093395 -222.474701)
		(end 359.297732 -222.272098)
		(width 0.0889)
		(layer "In6.Cu")
		(net "DMI_CPU0_PCH_RX_C_DP<5>")
	)
	(arc
		(start 363.24413 -217.064336)
		(mid 363.318046 -216.784834)
		(end 363.520482 -216.578434)
		(width 0.0889)
		(layer "In6.Cu")
		(net "DMI_CPU0_PCH_RX_C_DP<5>")
	)
	(arc
		(start 363.526832 -217.554048)
		(mid 363.319844 -217.347076)
		(end 363.24413 -217.064336)
		(width 0.0889)
		(layer "In6.Cu")
		(net "DMI_CPU0_PCH_RX_C_DP<5>")
	)
	(arc
		(start 362.212636 -219.830396)
		(mid 362.399834 -219.880539)
		(end 362.587032 -219.830396)
		(width 0.0889)
		(layer "In6.Cu")
		(net "DMI_CPU0_PCH_RX_C_DP<5>")
	)
	(arc
		(start 364.184438 -215.368124)
		(mid 364.216257 -215.207688)
		(end 364.30712 -215.071706)
		(width 0.0889)
		(layer "In6.Cu")
		(net "DMI_CPU0_PCH_RX_C_DP<5>")
	)
	(arc
		(start 362.774484 -219.496132)
		(mid 362.852595 -219.219183)
		(end 363.056932 -219.01658)
		(width 0.0889)
		(layer "In6.Cu")
		(net "DMI_CPU0_PCH_RX_C_DP<5>")
	)
	(arc
		(start 363.996986 -215.761062)
		(mid 364.131919 -215.627708)
		(end 364.184184 -215.44534)
		(width 0.0889)
		(layer "In6.Cu")
		(net "DMI_CPU0_PCH_RX_C_DP<5>")
	)
	(arc
		(start 357.60533 -226.831144)
		(mid 357.677565 -226.55462)
		(end 357.87584 -226.348798)
		(width 0.0889)
		(layer "In6.Cu")
		(net "DMI_CPU0_PCH_RX_C_DP<5>")
	)
	(arc
		(start 363.535722 -218.197684)
		(mid 363.714198 -217.878406)
		(end 363.535722 -217.559128)
		(width 0.0889)
		(layer "In6.Cu")
		(net "DMI_CPU0_PCH_RX_C_DP<5>")
	)
	(arc
		(start 359.776522 -221.453202)
		(mid 359.907436 -221.316842)
		(end 359.955084 -221.133924)
		(width 0.0889)
		(layer "In6.Cu")
		(net "DMI_CPU0_PCH_RX_C_DP<5>")
	)
	(arc
		(start 358.836722 -223.080834)
		(mid 358.967636 -222.944474)
		(end 359.015284 -222.761556)
		(width 0.0889)
		(layer "In6.Cu")
		(net "DMI_CPU0_PCH_RX_C_DP<5>")
	)
	(arc
		(start 358.075484 -225.99523)
		(mid 358.156395 -225.725102)
		(end 358.357678 -225.527616)
		(width 0.0889)
		(layer "In6.Cu")
		(net "DMI_CPU0_PCH_RX_C_DP<5>")
	)
	(arc
		(start 358.54513 -223.561402)
		(mid 358.624349 -223.286717)
		(end 358.827832 -223.085914)
		(width 0.0889)
		(layer "In6.Cu")
		(net "DMI_CPU0_PCH_RX_C_DP<5>")
	)
	(arc
		(start 359.48493 -221.94774)
		(mid 359.558921 -221.668174)
		(end 359.761536 -221.461838)
		(width 0.0889)
		(layer "In6.Cu")
		(net "DMI_CPU0_PCH_RX_C_DP<5>")
	)
	(arc
		(start 359.297732 -222.272098)
		(mid 359.432665 -222.138744)
		(end 359.48493 -221.956376)
		(width 0.0889)
		(layer "In6.Cu")
		(net "DMI_CPU0_PCH_RX_C_DP<5>")
	)
	(arc
		(start 362.595922 -219.825316)
		(mid 362.726836 -219.688956)
		(end 362.774484 -219.506038)
		(width 0.0889)
		(layer "In6.Cu")
		(net "DMI_CPU0_PCH_RX_C_DP<5>")
	)
	(arc
		(start 363.71403 -216.25052)
		(mid 363.785255 -215.97587)
		(end 363.980984 -215.77046)
		(width 0.0889)
		(layer "In6.Cu")
		(net "DMI_CPU0_PCH_RX_C_DP<5>")
	)
	(arc
		(start 357.896922 -226.336606)
		(mid 358.027836 -226.200246)
		(end 358.075484 -226.017328)
		(width 0.0889)
		(layer "In6.Cu")
		(net "DMI_CPU0_PCH_RX_C_DP<5>")
	)
	(arc
		(start 358.357932 -223.899984)
		(mid 358.492865 -223.76663)
		(end 358.54513 -223.584262)
		(width 0.0889)
		(layer "In6.Cu")
		(net "DMI_CPU0_PCH_RX_C_DP<5>")
	)
	(segment
		(start 355.82098 -228.1809)
		(end 355.82098 -227.645214)
		(width 0.13208)
		(layer "F.Cu")
		(net "DMI_CPU0_PCH_RX_C_DP<4>")
	)
	(segment
		(start 355.82098 -227.645214)
		(end 355.821234 -227.64496)
		(width 0.13208)
		(layer "F.Cu")
		(net "DMI_CPU0_PCH_RX_C_DP<4>")
	)
	(segment
		(start 346.032836 -72.5805)
		(end 346.032836 -74.997056)
		(width 0.13208)
		(layer "B.Cu")
		(net "DMI_CPU0_PCH_RX_C_DP<4>")
	)
	(segment
		(start 344.184732 -68.113148)
		(end 346.032836 -72.5805)
		(width 0.13208)
		(layer "B.Cu")
		(net "DMI_CPU0_PCH_RX_C_DP<4>")
	)
	(segment
		(start 346.032836 -74.997056)
		(end 340.162134 -80.867758)
		(width 0.13208)
		(layer "B.Cu")
		(net "DMI_CPU0_PCH_RX_C_DP<4>")
	)
	(segment
		(start 344.184732 -62.667388)
		(end 344.184732 -68.113148)
		(width 0.13208)
		(layer "B.Cu")
		(net "DMI_CPU0_PCH_RX_C_DP<4>")
	)
	(segment
		(start 340.162134 -80.867758)
		(end 340.162134 -81.661762)
		(width 0.13208)
		(layer "B.Cu")
		(net "DMI_CPU0_PCH_RX_C_DP<4>")
	)
	(segment
		(start 340.162134 -81.661762)
		(end 339.859874 -81.964022)
		(width 0.13208)
		(layer "B.Cu")
		(net "DMI_CPU0_PCH_RX_C_DP<4>")
	)
	(segment
		(start 343.840308 -62.322964)
		(end 344.184732 -62.667388)
		(width 0.13208)
		(layer "B.Cu")
		(net "DMI_CPU0_PCH_RX_C_DP<4>")
	)
	(segment
		(start 362.587032 -217.554048)
		(end 362.595922 -217.559128)
		(width 0.0889)
		(layer "In6.Cu")
		(net "DMI_CPU0_PCH_RX_C_DP<4>")
	)
	(segment
		(start 360.708956 -219.829634)
		(end 360.707432 -219.830396)
		(width 0.0889)
		(layer "In6.Cu")
		(net "DMI_CPU0_PCH_RX_C_DP<4>")
	)
	(segment
		(start 358.366822 -222.267018)
		(end 358.357932 -222.272098)
		(width 0.0889)
		(layer "In6.Cu")
		(net "DMI_CPU0_PCH_RX_C_DP<4>")
	)
	(segment
		(start 362.304584 -218.682316)
		(end 362.304584 -218.692222)
		(width 0.0889)
		(layer "In6.Cu")
		(net "DMI_CPU0_PCH_RX_C_DP<4>")
	)
	(segment
		(start 364.16488 -212.610954)
		(end 364.16488 -212.633052)
		(width 0.0889)
		(layer "In6.Cu")
		(net "DMI_CPU0_PCH_RX_C_DP<4>")
	)
	(segment
		(start 370.633244 -197.019672)
		(end 364.620556 -205.606396)
		(width 0.14732)
		(layer "In6.Cu")
		(net "DMI_CPU0_PCH_RX_C_DP<4>")
	)
	(segment
		(start 340.36889 -85.257386)
		(end 340.272624 -85.42147)
		(width 0.14732)
		(layer "In6.Cu")
		(net "DMI_CPU0_PCH_RX_C_DP<4>")
	)
	(segment
		(start 358.075484 -222.75165)
		(end 358.075484 -222.761556)
		(width 0.0889)
		(layer "In6.Cu")
		(net "DMI_CPU0_PCH_RX_C_DP<4>")
	)
	(segment
		(start 358.842564 -219.82176)
		(end 358.827832 -219.830396)
		(width 0.0889)
		(layer "In6.Cu")
		(net "DMI_CPU0_PCH_RX_C_DP<4>")
	)
	(segment
		(start 364.207044 -212.675216)
		(end 364.207044 -214.191342)
		(width 0.0889)
		(layer "In6.Cu")
		(net "DMI_CPU0_PCH_RX_C_DP<4>")
	)
	(segment
		(start 340.528148 -85.866986)
		(end 340.527894 -85.866986)
		(width 0.14732)
		(layer "In6.Cu")
		(net "DMI_CPU0_PCH_RX_C_DP<4>")
	)
	(segment
		(start 362.587032 -216.574878)
		(end 362.580936 -216.578434)
		(width 0.0889)
		(layer "In6.Cu")
		(net "DMI_CPU0_PCH_RX_C_DP<4>")
	)
	(segment
		(start 362.595922 -218.197684)
		(end 362.587032 -218.202764)
		(width 0.0889)
		(layer "In6.Cu")
		(net "DMI_CPU0_PCH_RX_C_DP<4>")
	)
	(segment
		(start 357.135684 -225.99523)
		(end 357.135684 -226.017328)
		(width 0.0889)
		(layer "In6.Cu")
		(net "DMI_CPU0_PCH_RX_C_DP<4>")
	)
	(segment
		(start 356.66553 -226.831144)
		(end 356.66553 -226.83978)
		(width 0.0889)
		(layer "In6.Cu")
		(net "DMI_CPU0_PCH_RX_C_DP<4>")
	)
	(segment
		(start 357.135684 -224.373948)
		(end 357.135684 -224.404936)
		(width 0.0889)
		(layer "In6.Cu")
		(net "DMI_CPU0_PCH_RX_C_DP<4>")
	)
	(segment
		(start 357.418894 -223.899476)
		(end 357.417878 -223.899984)
		(width 0.0889)
		(layer "In6.Cu")
		(net "DMI_CPU0_PCH_RX_C_DP<4>")
	)
	(segment
		(start 358.836722 -221.453202)
		(end 358.827832 -221.458282)
		(width 0.0889)
		(layer "In6.Cu")
		(net "DMI_CPU0_PCH_RX_C_DP<4>")
	)
	(segment
		(start 362.77423 -216.240614)
		(end 362.77423 -216.259156)
		(width 0.0889)
		(layer "In6.Cu")
		(net "DMI_CPU0_PCH_RX_C_DP<4>")
	)
	(segment
		(start 362.30433 -217.064336)
		(end 362.30433 -217.07856)
		(width 0.0889)
		(layer "In6.Cu")
		(net "DMI_CPU0_PCH_RX_C_DP<4>")
	)
	(segment
		(start 357.417878 -224.8789)
		(end 357.418894 -224.879408)
		(width 0.0889)
		(layer "In6.Cu")
		(net "DMI_CPU0_PCH_RX_C_DP<4>")
	)
	(segment
		(start 363.065568 -215.755982)
		(end 363.056678 -215.761062)
		(width 0.0889)
		(layer "In6.Cu")
		(net "DMI_CPU0_PCH_RX_C_DP<4>")
	)
	(segment
		(start 356.957122 -226.336606)
		(end 356.957122 -226.336352)
		(width 0.0889)
		(layer "In6.Cu")
		(net "DMI_CPU0_PCH_RX_C_DP<4>")
	)
	(segment
		(start 340.154514 -82.258662)
		(end 340.154514 -84.435188)
		(width 0.14732)
		(layer "In6.Cu")
		(net "DMI_CPU0_PCH_RX_C_DP<4>")
	)
	(segment
		(start 340.363556 -85.77072)
		(end 340.528148 -85.866986)
		(width 0.14732)
		(layer "In6.Cu")
		(net "DMI_CPU0_PCH_RX_C_DP<4>")
	)
	(segment
		(start 364.16488 -212.633052)
		(end 364.207044 -212.675216)
		(width 0.0889)
		(layer "In6.Cu")
		(net "DMI_CPU0_PCH_RX_C_DP<4>")
	)
	(segment
		(start 363.244384 -215.437466)
		(end 363.244384 -215.442546)
		(width 0.0889)
		(layer "In6.Cu")
		(net "DMI_CPU0_PCH_RX_C_DP<4>")
	)
	(segment
		(start 378.036836 -155.07589)
		(end 381.569468 -175.100234)
		(width 0.14732)
		(layer "In6.Cu")
		(net "DMI_CPU0_PCH_RX_C_DP<4>")
	)
	(segment
		(start 340.154514 -84.435188)
		(end 340.36889 -85.257386)
		(width 0.14732)
		(layer "In6.Cu")
		(net "DMI_CPU0_PCH_RX_C_DP<4>")
	)
	(segment
		(start 357.426768 -225.522536)
		(end 357.417878 -225.527616)
		(width 0.0889)
		(layer "In6.Cu")
		(net "DMI_CPU0_PCH_RX_C_DP<4>")
	)
	(segment
		(start 341.602822 -89.987882)
		(end 378.036836 -155.07589)
		(width 0.14732)
		(layer "In6.Cu")
		(net "DMI_CPU0_PCH_RX_C_DP<4>")
	)
	(segment
		(start 361.742736 -219.01658)
		(end 361.732322 -219.010484)
		(width 0.0889)
		(layer "In6.Cu")
		(net "DMI_CPU0_PCH_RX_C_DP<4>")
	)
	(segment
		(start 357.426768 -223.894904)
		(end 357.418894 -223.899476)
		(width 0.0889)
		(layer "In6.Cu")
		(net "DMI_CPU0_PCH_RX_C_DP<4>")
	)
	(segment
		(start 363.244384 -215.442546)
		(end 363.243876 -215.443054)
		(width 0.0889)
		(layer "In6.Cu")
		(net "DMI_CPU0_PCH_RX_C_DP<4>")
	)
	(segment
		(start 374.274842 -194.47002)
		(end 370.633244 -197.019672)
		(width 0.14732)
		(layer "In6.Cu")
		(net "DMI_CPU0_PCH_RX_C_DP<4>")
	)
	(segment
		(start 340.272624 -85.42147)
		(end 340.363556 -85.77072)
		(width 0.14732)
		(layer "In6.Cu")
		(net "DMI_CPU0_PCH_RX_C_DP<4>")
	)
	(segment
		(start 358.54513 -220.319854)
		(end 358.54513 -220.334078)
		(width 0.0889)
		(layer "In6.Cu")
		(net "DMI_CPU0_PCH_RX_C_DP<4>")
	)
	(segment
		(start 358.827832 -220.809566)
		(end 358.836722 -220.814646)
		(width 0.0889)
		(layer "In6.Cu")
		(net "DMI_CPU0_PCH_RX_C_DP<4>")
	)
	(segment
		(start 340.527894 -85.866986)
		(end 341.602822 -89.987882)
		(width 0.14732)
		(layer "In6.Cu")
		(net "DMI_CPU0_PCH_RX_C_DP<4>")
	)
	(segment
		(start 364.160054 -214.30488)
		(end 363.403896 -215.060784)
		(width 0.0889)
		(layer "In6.Cu")
		(net "DMI_CPU0_PCH_RX_C_DP<4>")
	)
	(segment
		(start 356.05593 -227.936806)
		(end 355.977698 -227.915978)
		(width 0.0889)
		(layer "In6.Cu")
		(net "DMI_CPU0_PCH_RX_C_DP<4>")
	)
	(segment
		(start 358.545384 -221.937834)
		(end 358.545384 -221.94774)
		(width 0.0889)
		(layer "In6.Cu")
		(net "DMI_CPU0_PCH_RX_C_DP<4>")
	)
	(segment
		(start 379.457966 -187.066936)
		(end 374.274842 -194.47002)
		(width 0.14732)
		(layer "In6.Cu")
		(net "DMI_CPU0_PCH_RX_C_DP<4>")
	)
	(segment
		(start 339.859874 -81.964022)
		(end 340.154514 -82.258662)
		(width 0.14732)
		(layer "In6.Cu")
		(net "DMI_CPU0_PCH_RX_C_DP<4>")
	)
	(segment
		(start 357.60533 -223.568006)
		(end 357.60533 -223.575626)
		(width 0.0889)
		(layer "In6.Cu")
		(net "DMI_CPU0_PCH_RX_C_DP<4>")
	)
	(segment
		(start 364.620556 -205.606396)
		(end 364.16488 -208.19618)
		(width 0.14732)
		(layer "In6.Cu")
		(net "DMI_CPU0_PCH_RX_C_DP<4>")
	)
	(segment
		(start 357.896922 -223.080834)
		(end 357.888032 -223.085914)
		(width 0.0889)
		(layer "In6.Cu")
		(net "DMI_CPU0_PCH_RX_C_DP<4>")
	)
	(segment
		(start 356.195884 -227.635054)
		(end 356.195884 -227.64496)
		(width 0.0889)
		(layer "In6.Cu")
		(net "DMI_CPU0_PCH_RX_C_DP<4>")
	)
	(segment
		(start 360.716322 -219.825316)
		(end 360.708956 -219.829634)
		(width 0.0889)
		(layer "In6.Cu")
		(net "DMI_CPU0_PCH_RX_C_DP<4>")
	)
	(segment
		(start 360.894884 -219.490544)
		(end 360.894884 -219.506038)
		(width 0.0889)
		(layer "In6.Cu")
		(net "DMI_CPU0_PCH_RX_C_DP<4>")
	)
	(segment
		(start 357.418894 -224.879408)
		(end 357.426768 -224.88398)
		(width 0.0889)
		(layer "In6.Cu")
		(net "DMI_CPU0_PCH_RX_C_DP<4>")
	)
	(segment
		(start 356.957122 -226.336352)
		(end 356.942136 -226.345242)
		(width 0.0889)
		(layer "In6.Cu")
		(net "DMI_CPU0_PCH_RX_C_DP<4>")
	)
	(segment
		(start 355.977698 -227.915978)
		(end 355.821234 -227.64496)
		(width 0.0889)
		(layer "In6.Cu")
		(net "DMI_CPU0_PCH_RX_C_DP<4>")
	)
	(segment
		(start 381.569468 -175.100234)
		(end 379.457966 -187.066936)
		(width 0.14732)
		(layer "In6.Cu")
		(net "DMI_CPU0_PCH_RX_C_DP<4>")
	)
	(segment
		(start 364.16488 -208.19618)
		(end 364.16488 -212.610954)
		(width 0.14732)
		(layer "In6.Cu")
		(net "DMI_CPU0_PCH_RX_C_DP<4>")
	)
	(segment
		(start 358.827832 -219.830396)
		(end 358.821736 -219.833952)
		(width 0.0889)
		(layer "In6.Cu")
		(net "DMI_CPU0_PCH_RX_C_DP<4>")
	)
	(segment
		(start 362.126022 -219.0115)
		(end 362.117132 -219.01658)
		(width 0.0889)
		(layer "In6.Cu")
		(net "DMI_CPU0_PCH_RX_C_DP<4>")
	)
	(arc
		(start 357.426768 -224.88398)
		(mid 357.557682 -225.02034)
		(end 357.60533 -225.203258)
		(width 0.0889)
		(layer "In6.Cu")
		(net "DMI_CPU0_PCH_RX_C_DP<4>")
	)
	(arc
		(start 362.304584 -218.692222)
		(mid 362.256905 -218.875122)
		(end 362.126022 -219.0115)
		(width 0.0889)
		(layer "In6.Cu")
		(net "DMI_CPU0_PCH_RX_C_DP<4>")
	)
	(arc
		(start 356.942136 -226.345242)
		(mid 356.739549 -226.551593)
		(end 356.66553 -226.831144)
		(width 0.0889)
		(layer "In6.Cu")
		(net "DMI_CPU0_PCH_RX_C_DP<4>")
	)
	(arc
		(start 361.177078 -219.01658)
		(mid 360.974255 -219.216811)
		(end 360.894884 -219.490544)
		(width 0.0889)
		(layer "In6.Cu")
		(net "DMI_CPU0_PCH_RX_C_DP<4>")
	)
	(arc
		(start 356.195884 -227.64496)
		(mid 356.159024 -227.806757)
		(end 356.05593 -227.936806)
		(width 0.0889)
		(layer "In6.Cu")
		(net "DMI_CPU0_PCH_RX_C_DP<4>")
	)
	(arc
		(start 360.894884 -219.506038)
		(mid 360.847205 -219.688938)
		(end 360.716322 -219.825316)
		(width 0.0889)
		(layer "In6.Cu")
		(net "DMI_CPU0_PCH_RX_C_DP<4>")
	)
	(arc
		(start 362.77423 -216.259156)
		(mid 362.72196 -216.441521)
		(end 362.587032 -216.574878)
		(width 0.0889)
		(layer "In6.Cu")
		(net "DMI_CPU0_PCH_RX_C_DP<4>")
	)
	(arc
		(start 357.60533 -225.203258)
		(mid 357.605278 -225.210625)
		(end 357.605076 -225.21799)
		(width 0.0889)
		(layer "In6.Cu")
		(net "DMI_CPU0_PCH_RX_C_DP<4>")
	)
	(arc
		(start 358.827832 -221.458282)
		(mid 358.623497 -221.660887)
		(end 358.545384 -221.937834)
		(width 0.0889)
		(layer "In6.Cu")
		(net "DMI_CPU0_PCH_RX_C_DP<4>")
	)
	(arc
		(start 358.545384 -221.94774)
		(mid 358.497705 -222.13064)
		(end 358.366822 -222.267018)
		(width 0.0889)
		(layer "In6.Cu")
		(net "DMI_CPU0_PCH_RX_C_DP<4>")
	)
	(arc
		(start 359.015284 -221.140528)
		(mid 358.966031 -221.319728)
		(end 358.836722 -221.453202)
		(width 0.0889)
		(layer "In6.Cu")
		(net "DMI_CPU0_PCH_RX_C_DP<4>")
	)
	(arc
		(start 358.54513 -220.334078)
		(mid 358.624349 -220.608763)
		(end 358.827832 -220.809566)
		(width 0.0889)
		(layer "In6.Cu")
		(net "DMI_CPU0_PCH_RX_C_DP<4>")
	)
	(arc
		(start 357.135684 -224.404936)
		(mid 357.215054 -224.67867)
		(end 357.417878 -224.8789)
		(width 0.0889)
		(layer "In6.Cu")
		(net "DMI_CPU0_PCH_RX_C_DP<4>")
	)
	(arc
		(start 357.417878 -223.899984)
		(mid 357.215055 -224.100215)
		(end 357.135684 -224.373948)
		(width 0.0889)
		(layer "In6.Cu")
		(net "DMI_CPU0_PCH_RX_C_DP<4>")
	)
	(arc
		(start 364.207044 -214.191342)
		(mid 364.19484 -214.252788)
		(end 364.160054 -214.30488)
		(width 0.0889)
		(layer "In6.Cu")
		(net "DMI_CPU0_PCH_RX_C_DP<4>")
	)
	(arc
		(start 359.767632 -219.830396)
		(mid 359.580434 -219.880539)
		(end 359.393236 -219.830396)
		(width 0.0889)
		(layer "In6.Cu")
		(net "DMI_CPU0_PCH_RX_C_DP<4>")
	)
	(arc
		(start 362.30433 -217.07856)
		(mid 362.383549 -217.353245)
		(end 362.587032 -217.554048)
		(width 0.0889)
		(layer "In6.Cu")
		(net "DMI_CPU0_PCH_RX_C_DP<4>")
	)
	(arc
		(start 363.403896 -215.060784)
		(mid 363.29057 -215.234913)
		(end 363.244384 -215.437466)
		(width 0.0889)
		(layer "In6.Cu")
		(net "DMI_CPU0_PCH_RX_C_DP<4>")
	)
	(arc
		(start 363.243876 -215.443054)
		(mid 363.194828 -215.622385)
		(end 363.065568 -215.755982)
		(width 0.0889)
		(layer "In6.Cu")
		(net "DMI_CPU0_PCH_RX_C_DP<4>")
	)
	(arc
		(start 357.135684 -226.017328)
		(mid 357.088005 -226.200228)
		(end 356.957122 -226.336606)
		(width 0.0889)
		(layer "In6.Cu")
		(net "DMI_CPU0_PCH_RX_C_DP<4>")
	)
	(arc
		(start 359.393236 -219.830396)
		(mid 359.119037 -219.754561)
		(end 358.842564 -219.82176)
		(width 0.0889)
		(layer "In6.Cu")
		(net "DMI_CPU0_PCH_RX_C_DP<4>")
	)
	(arc
		(start 362.774484 -217.869008)
		(mid 362.774572 -217.877009)
		(end 362.774484 -217.88501)
		(width 0.0889)
		(layer "In6.Cu")
		(net "DMI_CPU0_PCH_RX_C_DP<4>")
	)
	(arc
		(start 362.117132 -219.01658)
		(mid 361.929934 -219.066723)
		(end 361.742736 -219.01658)
		(width 0.0889)
		(layer "In6.Cu")
		(net "DMI_CPU0_PCH_RX_C_DP<4>")
	)
	(arc
		(start 361.732322 -219.010484)
		(mid 361.45389 -218.940638)
		(end 361.177078 -219.01658)
		(width 0.0889)
		(layer "In6.Cu")
		(net "DMI_CPU0_PCH_RX_C_DP<4>")
	)
	(arc
		(start 360.707432 -219.830396)
		(mid 360.520234 -219.880539)
		(end 360.333036 -219.830396)
		(width 0.0889)
		(layer "In6.Cu")
		(net "DMI_CPU0_PCH_RX_C_DP<4>")
	)
	(arc
		(start 356.478332 -227.155502)
		(mid 356.273997 -227.358107)
		(end 356.195884 -227.635054)
		(width 0.0889)
		(layer "In6.Cu")
		(net "DMI_CPU0_PCH_RX_C_DP<4>")
	)
	(arc
		(start 358.836722 -220.814646)
		(mid 358.965316 -220.94692)
		(end 359.015284 -221.124526)
		(width 0.0889)
		(layer "In6.Cu")
		(net "DMI_CPU0_PCH_RX_C_DP<4>")
	)
	(arc
		(start 359.015284 -221.124526)
		(mid 359.015372 -221.132527)
		(end 359.015284 -221.140528)
		(width 0.0889)
		(layer "In6.Cu")
		(net "DMI_CPU0_PCH_RX_C_DP<4>")
	)
	(arc
		(start 357.60533 -223.575626)
		(mid 357.557651 -223.758526)
		(end 357.426768 -223.894904)
		(width 0.0889)
		(layer "In6.Cu")
		(net "DMI_CPU0_PCH_RX_C_DP<4>")
	)
	(arc
		(start 360.333036 -219.830396)
		(mid 360.050334 -219.75462)
		(end 359.767632 -219.830396)
		(width 0.0889)
		(layer "In6.Cu")
		(net "DMI_CPU0_PCH_RX_C_DP<4>")
	)
	(arc
		(start 358.075484 -222.761556)
		(mid 358.027805 -222.944456)
		(end 357.896922 -223.080834)
		(width 0.0889)
		(layer "In6.Cu")
		(net "DMI_CPU0_PCH_RX_C_DP<4>")
	)
	(arc
		(start 363.056678 -215.761062)
		(mid 362.852343 -215.963667)
		(end 362.77423 -216.240614)
		(width 0.0889)
		(layer "In6.Cu")
		(net "DMI_CPU0_PCH_RX_C_DP<4>")
	)
	(arc
		(start 358.821736 -219.833952)
		(mid 358.619149 -220.040303)
		(end 358.54513 -220.319854)
		(width 0.0889)
		(layer "In6.Cu")
		(net "DMI_CPU0_PCH_RX_C_DP<4>")
	)
	(arc
		(start 357.605076 -225.21799)
		(mid 357.554022 -225.39257)
		(end 357.426768 -225.522536)
		(width 0.0889)
		(layer "In6.Cu")
		(net "DMI_CPU0_PCH_RX_C_DP<4>")
	)
	(arc
		(start 362.580936 -216.578434)
		(mid 362.378349 -216.784785)
		(end 362.30433 -217.064336)
		(width 0.0889)
		(layer "In6.Cu")
		(net "DMI_CPU0_PCH_RX_C_DP<4>")
	)
	(arc
		(start 362.774484 -217.88501)
		(mid 362.725231 -218.06421)
		(end 362.595922 -218.197684)
		(width 0.0889)
		(layer "In6.Cu")
		(net "DMI_CPU0_PCH_RX_C_DP<4>")
	)
	(arc
		(start 362.595922 -217.559128)
		(mid 362.724516 -217.691402)
		(end 362.774484 -217.869008)
		(width 0.0889)
		(layer "In6.Cu")
		(net "DMI_CPU0_PCH_RX_C_DP<4>")
	)
	(arc
		(start 358.357932 -222.272098)
		(mid 358.153597 -222.474703)
		(end 358.075484 -222.75165)
		(width 0.0889)
		(layer "In6.Cu")
		(net "DMI_CPU0_PCH_RX_C_DP<4>")
	)
	(arc
		(start 357.417878 -225.527616)
		(mid 357.216596 -225.725103)
		(end 357.135684 -225.99523)
		(width 0.0889)
		(layer "In6.Cu")
		(net "DMI_CPU0_PCH_RX_C_DP<4>")
	)
	(arc
		(start 357.888032 -223.085914)
		(mid 357.68296 -223.289593)
		(end 357.60533 -223.568006)
		(width 0.0889)
		(layer "In6.Cu")
		(net "DMI_CPU0_PCH_RX_C_DP<4>")
	)
	(arc
		(start 362.587032 -218.202764)
		(mid 362.382697 -218.405369)
		(end 362.304584 -218.682316)
		(width 0.0889)
		(layer "In6.Cu")
		(net "DMI_CPU0_PCH_RX_C_DP<4>")
	)
	(arc
		(start 356.66553 -226.83978)
		(mid 356.61326 -227.022145)
		(end 356.478332 -227.155502)
		(width 0.0889)
		(layer "In6.Cu")
		(net "DMI_CPU0_PCH_RX_C_DP<4>")
	)
	(segment
		(start 355.351334 -226.831398)
		(end 355.35108 -226.831144)
		(width 0.13208)
		(layer "F.Cu")
		(net "DMI_CPU0_PCH_RX_C_DP<3>")
	)
	(segment
		(start 355.351334 -227.367084)
		(end 355.351334 -226.831398)
		(width 0.13208)
		(layer "F.Cu")
		(net "DMI_CPU0_PCH_RX_C_DP<3>")
	)
	(segment
		(start 338.26323 -84.484464)
		(end 338.56549 -84.182204)
		(width 0.13208)
		(layer "B.Cu")
		(net "DMI_CPU0_PCH_RX_C_DP<3>")
	)
	(segment
		(start 342.579452 -68.254372)
		(end 342.579452 -64.682624)
		(width 0.13208)
		(layer "B.Cu")
		(net "DMI_CPU0_PCH_RX_C_DP<3>")
	)
	(segment
		(start 338.56549 -84.182204)
		(end 338.56549 -80.271112)
		(width 0.13208)
		(layer "B.Cu")
		(net "DMI_CPU0_PCH_RX_C_DP<3>")
	)
	(segment
		(start 342.579452 -64.682624)
		(end 342.251792 -64.354964)
		(width 0.13208)
		(layer "B.Cu")
		(net "DMI_CPU0_PCH_RX_C_DP<3>")
	)
	(segment
		(start 343.312496 -70.024244)
		(end 342.579452 -68.254372)
		(width 0.13208)
		(layer "B.Cu")
		(net "DMI_CPU0_PCH_RX_C_DP<3>")
	)
	(segment
		(start 343.26322 -72.13473)
		(end 343.312496 -71.886826)
		(width 0.13208)
		(layer "B.Cu")
		(net "DMI_CPU0_PCH_RX_C_DP<3>")
	)
	(segment
		(start 343.312496 -71.886826)
		(end 343.312496 -70.024244)
		(width 0.13208)
		(layer "B.Cu")
		(net "DMI_CPU0_PCH_RX_C_DP<3>")
	)
	(segment
		(start 338.56549 -80.271112)
		(end 342.687656 -76.148946)
		(width 0.13208)
		(layer "B.Cu")
		(net "DMI_CPU0_PCH_RX_C_DP<3>")
	)
	(segment
		(start 342.687656 -73.52411)
		(end 343.26322 -72.13473)
		(width 0.13208)
		(layer "B.Cu")
		(net "DMI_CPU0_PCH_RX_C_DP<3>")
	)
	(segment
		(start 342.687656 -76.148946)
		(end 342.687656 -73.52411)
		(width 0.13208)
		(layer "B.Cu")
		(net "DMI_CPU0_PCH_RX_C_DP<3>")
	)
	(segment
		(start 338.6455 -86.695026)
		(end 338.810346 -86.791038)
		(width 0.14732)
		(layer "In6.Cu")
		(net "DMI_CPU0_PCH_RX_C_DP<3>")
	)
	(segment
		(start 359.297986 -219.01658)
		(end 359.277412 -219.028518)
		(width 0.0889)
		(layer "In6.Cu")
		(net "DMI_CPU0_PCH_RX_C_DP<3>")
	)
	(segment
		(start 339.062568 -87.749126)
		(end 339.44306 -89.193116)
		(width 0.14732)
		(layer "In6.Cu")
		(net "DMI_CPU0_PCH_RX_C_DP<3>")
	)
	(segment
		(start 363.065568 -208.675478)
		(end 363.065568 -211.59343)
		(width 0.14732)
		(layer "In6.Cu")
		(net "DMI_CPU0_PCH_RX_C_DP<3>")
	)
	(segment
		(start 356.66553 -223.561402)
		(end 356.66553 -223.584262)
		(width 0.0889)
		(layer "In6.Cu")
		(net "DMI_CPU0_PCH_RX_C_DP<3>")
	)
	(segment
		(start 357.888032 -220.809566)
		(end 357.888794 -220.810074)
		(width 0.0889)
		(layer "In6.Cu")
		(net "DMI_CPU0_PCH_RX_C_DP<3>")
	)
	(segment
		(start 363.107732 -213.270846)
		(end 363.107732 -213.565486)
		(width 0.0889)
		(layer "In6.Cu")
		(net "DMI_CPU0_PCH_RX_C_DP<3>")
	)
	(segment
		(start 363.008672 -212.907626)
		(end 363.008672 -213.171786)
		(width 0.0889)
		(layer "In6.Cu")
		(net "DMI_CPU0_PCH_RX_C_DP<3>")
	)
	(segment
		(start 363.008672 -213.171786)
		(end 363.107732 -213.270846)
		(width 0.0889)
		(layer "In6.Cu")
		(net "DMI_CPU0_PCH_RX_C_DP<3>")
	)
	(segment
		(start 371.615716 -195.248022)
		(end 369.487958 -196.737986)
		(width 0.14732)
		(layer "In6.Cu")
		(net "DMI_CPU0_PCH_RX_C_DP<3>")
	)
	(segment
		(start 360.703114 -218.205304)
		(end 360.701336 -218.20632)
		(width 0.0889)
		(layer "In6.Cu")
		(net "DMI_CPU0_PCH_RX_C_DP<3>")
	)
	(segment
		(start 363.107732 -214.401908)
		(end 362.504228 -215.005412)
		(width 0.0889)
		(layer "In6.Cu")
		(net "DMI_CPU0_PCH_RX_C_DP<3>")
	)
	(segment
		(start 356.017322 -226.336606)
		(end 356.009194 -226.341178)
		(width 0.0889)
		(layer "In6.Cu")
		(net "DMI_CPU0_PCH_RX_C_DP<3>")
	)
	(segment
		(start 338.55787 -85.83295)
		(end 338.649564 -86.181692)
		(width 0.14732)
		(layer "In6.Cu")
		(net "DMI_CPU0_PCH_RX_C_DP<3>")
	)
	(segment
		(start 358.075484 -219.496132)
		(end 358.075484 -219.506038)
		(width 0.0889)
		(layer "In6.Cu")
		(net "DMI_CPU0_PCH_RX_C_DP<3>")
	)
	(segment
		(start 338.55787 -84.779104)
		(end 338.55787 -85.83295)
		(width 0.14732)
		(layer "In6.Cu")
		(net "DMI_CPU0_PCH_RX_C_DP<3>")
	)
	(segment
		(start 357.888032 -221.458282)
		(end 357.885492 -221.459552)
		(width 0.0889)
		(layer "In6.Cu")
		(net "DMI_CPU0_PCH_RX_C_DP<3>")
	)
	(segment
		(start 357.888032 -219.830396)
		(end 357.884222 -219.832682)
		(width 0.0889)
		(layer "In6.Cu")
		(net "DMI_CPU0_PCH_RX_C_DP<3>")
	)
	(segment
		(start 361.647232 -217.554048)
		(end 361.656122 -217.559128)
		(width 0.0889)
		(layer "In6.Cu")
		(net "DMI_CPU0_PCH_RX_C_DP<3>")
	)
	(segment
		(start 360.705146 -218.204034)
		(end 360.703114 -218.205304)
		(width 0.0889)
		(layer "In6.Cu")
		(net "DMI_CPU0_PCH_RX_C_DP<3>")
	)
	(segment
		(start 363.008672 -213.928706)
		(end 363.107732 -214.027766)
		(width 0.0889)
		(layer "In6.Cu")
		(net "DMI_CPU0_PCH_RX_C_DP<3>")
	)
	(segment
		(start 369.487958 -196.737986)
		(end 366.605058 -200.855072)
		(width 0.14732)
		(layer "In6.Cu")
		(net "DMI_CPU0_PCH_RX_C_DP<3>")
	)
	(segment
		(start 362.304584 -215.426798)
		(end 362.304584 -215.44534)
		(width 0.0889)
		(layer "In6.Cu")
		(net "DMI_CPU0_PCH_RX_C_DP<3>")
	)
	(segment
		(start 338.90204 -87.13978)
		(end 338.806282 -87.304118)
		(width 0.14732)
		(layer "In6.Cu")
		(net "DMI_CPU0_PCH_RX_C_DP<3>")
	)
	(segment
		(start 363.008672 -212.445346)
		(end 363.107732 -212.544406)
		(width 0.0889)
		(layer "In6.Cu")
		(net "DMI_CPU0_PCH_RX_C_DP<3>")
	)
	(segment
		(start 356.957122 -223.080834)
		(end 356.948232 -223.085914)
		(width 0.0889)
		(layer "In6.Cu")
		(net "DMI_CPU0_PCH_RX_C_DP<3>")
	)
	(segment
		(start 356.195884 -225.99523)
		(end 356.195884 -226.017328)
		(width 0.0889)
		(layer "In6.Cu")
		(net "DMI_CPU0_PCH_RX_C_DP<3>")
	)
	(segment
		(start 355.547168 -227.150422)
		(end 355.539294 -227.154994)
		(width 0.0889)
		(layer "In6.Cu")
		(net "DMI_CPU0_PCH_RX_C_DP<3>")
	)
	(segment
		(start 339.062822 -87.749126)
		(end 339.062568 -87.749126)
		(width 0.14732)
		(layer "In6.Cu")
		(net "DMI_CPU0_PCH_RX_C_DP<3>")
	)
	(segment
		(start 356.195884 -224.379536)
		(end 356.195884 -224.404936)
		(width 0.0889)
		(layer "In6.Cu")
		(net "DMI_CPU0_PCH_RX_C_DP<3>")
	)
	(segment
		(start 361.36453 -217.064336)
		(end 361.36453 -217.071956)
		(width 0.0889)
		(layer "In6.Cu")
		(net "DMI_CPU0_PCH_RX_C_DP<3>")
	)
	(segment
		(start 357.885492 -221.459552)
		(end 357.878888 -221.463616)
		(width 0.0889)
		(layer "In6.Cu")
		(net "DMI_CPU0_PCH_RX_C_DP<3>")
	)
	(segment
		(start 338.26323 -84.484464)
		(end 338.55787 -84.779104)
		(width 0.14732)
		(layer "In6.Cu")
		(net "DMI_CPU0_PCH_RX_C_DP<3>")
	)
	(segment
		(start 356.008432 -226.341686)
		(end 356.004622 -226.343972)
		(width 0.0889)
		(layer "In6.Cu")
		(net "DMI_CPU0_PCH_RX_C_DP<3>")
	)
	(segment
		(start 360.246168 -219.0115)
		(end 360.237278 -219.01658)
		(width 0.0889)
		(layer "In6.Cu")
		(net "DMI_CPU0_PCH_RX_C_DP<3>")
	)
	(segment
		(start 357.418894 -222.27159)
		(end 357.417878 -222.272098)
		(width 0.0889)
		(layer "In6.Cu")
		(net "DMI_CPU0_PCH_RX_C_DP<3>")
	)
	(segment
		(start 366.605058 -200.855072)
		(end 363.7153 -204.982064)
		(width 0.14732)
		(layer "In6.Cu")
		(net "DMI_CPU0_PCH_RX_C_DP<3>")
	)
	(segment
		(start 355.215698 -227.18014)
		(end 355.194616 -227.102162)
		(width 0.0889)
		(layer "In6.Cu")
		(net "DMI_CPU0_PCH_RX_C_DP<3>")
	)
	(segment
		(start 380.56058 -175.70958)
		(end 378.612908 -186.746388)
		(width 0.14732)
		(layer "In6.Cu")
		(net "DMI_CPU0_PCH_RX_C_DP<3>")
	)
	(segment
		(start 377.001532 -155.538678)
		(end 380.56058 -175.70958)
		(width 0.14732)
		(layer "In6.Cu")
		(net "DMI_CPU0_PCH_RX_C_DP<3>")
	)
	(segment
		(start 363.107732 -212.082126)
		(end 363.008672 -212.181186)
		(width 0.0889)
		(layer "In6.Cu")
		(net "DMI_CPU0_PCH_RX_C_DP<3>")
	)
	(segment
		(start 356.009194 -226.341178)
		(end 356.008432 -226.341686)
		(width 0.0889)
		(layer "In6.Cu")
		(net "DMI_CPU0_PCH_RX_C_DP<3>")
	)
	(segment
		(start 358.934258 -219.023438)
		(end 358.923336 -219.016834)
		(width 0.0889)
		(layer "In6.Cu")
		(net "DMI_CPU0_PCH_RX_C_DP<3>")
	)
	(segment
		(start 355.194616 -227.102162)
		(end 355.35108 -226.831144)
		(width 0.0889)
		(layer "In6.Cu")
		(net "DMI_CPU0_PCH_RX_C_DP<3>")
	)
	(segment
		(start 360.722164 -218.194128)
		(end 360.707432 -218.202764)
		(width 0.0889)
		(layer "In6.Cu")
		(net "DMI_CPU0_PCH_RX_C_DP<3>")
	)
	(segment
		(start 363.107732 -212.544406)
		(end 363.107732 -212.808566)
		(width 0.0889)
		(layer "In6.Cu")
		(net "DMI_CPU0_PCH_RX_C_DP<3>")
	)
	(segment
		(start 362.117386 -215.761062)
		(end 362.101384 -215.77046)
		(width 0.0889)
		(layer "In6.Cu")
		(net "DMI_CPU0_PCH_RX_C_DP<3>")
	)
	(segment
		(start 373.664734 -193.813176)
		(end 371.61597 -195.248022)
		(width 0.14732)
		(layer "In6.Cu")
		(net "DMI_CPU0_PCH_RX_C_DP<3>")
	)
	(segment
		(start 360.707432 -218.202764)
		(end 360.705146 -218.204034)
		(width 0.0889)
		(layer "In6.Cu")
		(net "DMI_CPU0_PCH_RX_C_DP<3>")
	)
	(segment
		(start 357.888794 -220.810074)
		(end 357.896922 -220.814646)
		(width 0.0889)
		(layer "In6.Cu")
		(net "DMI_CPU0_PCH_RX_C_DP<3>")
	)
	(segment
		(start 358.358186 -219.016834)
		(end 358.357932 -219.01658)
		(width 0.0889)
		(layer "In6.Cu")
		(net "DMI_CPU0_PCH_RX_C_DP<3>")
	)
	(segment
		(start 361.655868 -216.569798)
		(end 361.646978 -216.574878)
		(width 0.0889)
		(layer "In6.Cu")
		(net "DMI_CPU0_PCH_RX_C_DP<3>")
	)
	(segment
		(start 338.810346 -86.791038)
		(end 338.90204 -87.13978)
		(width 0.14732)
		(layer "In6.Cu")
		(net "DMI_CPU0_PCH_RX_C_DP<3>")
	)
	(segment
		(start 359.277412 -219.028518)
		(end 359.27538 -219.029534)
		(width 0.0889)
		(layer "In6.Cu")
		(net "DMI_CPU0_PCH_RX_C_DP<3>")
	)
	(segment
		(start 363.107732 -213.565486)
		(end 363.008672 -213.664546)
		(width 0.0889)
		(layer "In6.Cu")
		(net "DMI_CPU0_PCH_RX_C_DP<3>")
	)
	(segment
		(start 361.656122 -218.197684)
		(end 361.647232 -218.202764)
		(width 0.0889)
		(layer "In6.Cu")
		(net "DMI_CPU0_PCH_RX_C_DP<3>")
	)
	(segment
		(start 371.61597 -195.248022)
		(end 371.615716 -195.248022)
		(width 0.14732)
		(layer "In6.Cu")
		(net "DMI_CPU0_PCH_RX_C_DP<3>")
	)
	(segment
		(start 357.878888 -221.463616)
		(end 357.87584 -221.465394)
		(width 0.0889)
		(layer "In6.Cu")
		(net "DMI_CPU0_PCH_RX_C_DP<3>")
	)
	(segment
		(start 357.896922 -221.453202)
		(end 357.888032 -221.458282)
		(width 0.0889)
		(layer "In6.Cu")
		(net "DMI_CPU0_PCH_RX_C_DP<3>")
	)
	(segment
		(start 363.008672 -213.664546)
		(end 363.008672 -213.928706)
		(width 0.0889)
		(layer "In6.Cu")
		(net "DMI_CPU0_PCH_RX_C_DP<3>")
	)
	(segment
		(start 363.008672 -212.181186)
		(end 363.008672 -212.445346)
		(width 0.0889)
		(layer "In6.Cu")
		(net "DMI_CPU0_PCH_RX_C_DP<3>")
	)
	(segment
		(start 357.884222 -219.832682)
		(end 357.87584 -219.837508)
		(width 0.0889)
		(layer "In6.Cu")
		(net "DMI_CPU0_PCH_RX_C_DP<3>")
	)
	(segment
		(start 363.065568 -211.615528)
		(end 363.107732 -211.657692)
		(width 0.0889)
		(layer "In6.Cu")
		(net "DMI_CPU0_PCH_RX_C_DP<3>")
	)
	(segment
		(start 357.426768 -222.267018)
		(end 357.418894 -222.27159)
		(width 0.0889)
		(layer "In6.Cu")
		(net "DMI_CPU0_PCH_RX_C_DP<3>")
	)
	(segment
		(start 378.612908 -186.746388)
		(end 373.664734 -193.813176)
		(width 0.14732)
		(layer "In6.Cu")
		(net "DMI_CPU0_PCH_RX_C_DP<3>")
	)
	(segment
		(start 363.107732 -211.657692)
		(end 363.107732 -212.082126)
		(width 0.0889)
		(layer "In6.Cu")
		(net "DMI_CPU0_PCH_RX_C_DP<3>")
	)
	(segment
		(start 356.478078 -224.8789)
		(end 356.486968 -224.88398)
		(width 0.0889)
		(layer "In6.Cu")
		(net "DMI_CPU0_PCH_RX_C_DP<3>")
	)
	(segment
		(start 357.135684 -222.746062)
		(end 357.135684 -222.761556)
		(width 0.0889)
		(layer "In6.Cu")
		(net "DMI_CPU0_PCH_RX_C_DP<3>")
	)
	(segment
		(start 338.553806 -86.34603)
		(end 338.6455 -86.695026)
		(width 0.14732)
		(layer "In6.Cu")
		(net "DMI_CPU0_PCH_RX_C_DP<3>")
	)
	(segment
		(start 357.896922 -219.825316)
		(end 357.888032 -219.830396)
		(width 0.0889)
		(layer "In6.Cu")
		(net "DMI_CPU0_PCH_RX_C_DP<3>")
	)
	(segment
		(start 363.107732 -212.808566)
		(end 363.008672 -212.907626)
		(width 0.0889)
		(layer "In6.Cu")
		(net "DMI_CPU0_PCH_RX_C_DP<3>")
	)
	(segment
		(start 361.646978 -216.574878)
		(end 361.640882 -216.578434)
		(width 0.0889)
		(layer "In6.Cu")
		(net "DMI_CPU0_PCH_RX_C_DP<3>")
	)
	(segment
		(start 339.44306 -89.193116)
		(end 377.001532 -155.538678)
		(width 0.14732)
		(layer "In6.Cu")
		(net "DMI_CPU0_PCH_RX_C_DP<3>")
	)
	(segment
		(start 357.60533 -220.319854)
		(end 357.60533 -220.327474)
		(width 0.0889)
		(layer "In6.Cu")
		(net "DMI_CPU0_PCH_RX_C_DP<3>")
	)
	(segment
		(start 363.107732 -214.027766)
		(end 363.107732 -214.401908)
		(width 0.0889)
		(layer "In6.Cu")
		(net "DMI_CPU0_PCH_RX_C_DP<3>")
	)
	(segment
		(start 356.486968 -225.522536)
		(end 356.478078 -225.527616)
		(width 0.0889)
		(layer "In6.Cu")
		(net "DMI_CPU0_PCH_RX_C_DP<3>")
	)
	(segment
		(start 338.649564 -86.181692)
		(end 338.553806 -86.34603)
		(width 0.14732)
		(layer "In6.Cu")
		(net "DMI_CPU0_PCH_RX_C_DP<3>")
	)
	(segment
		(start 338.806282 -87.304118)
		(end 338.897976 -87.653114)
		(width 0.14732)
		(layer "In6.Cu")
		(net "DMI_CPU0_PCH_RX_C_DP<3>")
	)
	(segment
		(start 356.004622 -226.343972)
		(end 355.99624 -226.348798)
		(width 0.0889)
		(layer "In6.Cu")
		(net "DMI_CPU0_PCH_RX_C_DP<3>")
	)
	(segment
		(start 363.065568 -211.59343)
		(end 363.065568 -211.615528)
		(width 0.0889)
		(layer "In6.Cu")
		(net "DMI_CPU0_PCH_RX_C_DP<3>")
	)
	(segment
		(start 363.7153 -204.982064)
		(end 363.065568 -208.675478)
		(width 0.14732)
		(layer "In6.Cu")
		(net "DMI_CPU0_PCH_RX_C_DP<3>")
	)
	(segment
		(start 355.539294 -227.154994)
		(end 355.538278 -227.155502)
		(width 0.0889)
		(layer "In6.Cu")
		(net "DMI_CPU0_PCH_RX_C_DP<3>")
	)
	(segment
		(start 338.897976 -87.653114)
		(end 339.062822 -87.749126)
		(width 0.14732)
		(layer "In6.Cu")
		(net "DMI_CPU0_PCH_RX_C_DP<3>")
	)
	(arc
		(start 356.66553 -223.584262)
		(mid 356.61326 -223.766627)
		(end 356.478332 -223.899984)
		(width 0.0889)
		(layer "In6.Cu")
		(net "DMI_CPU0_PCH_RX_C_DP<3>")
	)
	(arc
		(start 355.538278 -227.155502)
		(mid 355.37979 -227.204435)
		(end 355.215698 -227.18014)
		(width 0.0889)
		(layer "In6.Cu")
		(net "DMI_CPU0_PCH_RX_C_DP<3>")
	)
	(arc
		(start 361.656122 -217.559128)
		(mid 361.834719 -217.878406)
		(end 361.656122 -218.197684)
		(width 0.0889)
		(layer "In6.Cu")
		(net "DMI_CPU0_PCH_RX_C_DP<3>")
	)
	(arc
		(start 361.647232 -218.202764)
		(mid 361.460034 -218.252907)
		(end 361.272836 -218.202764)
		(width 0.0889)
		(layer "In6.Cu")
		(net "DMI_CPU0_PCH_RX_C_DP<3>")
	)
	(arc
		(start 356.486968 -224.88398)
		(mid 356.617882 -225.02034)
		(end 356.66553 -225.203258)
		(width 0.0889)
		(layer "In6.Cu")
		(net "DMI_CPU0_PCH_RX_C_DP<3>")
	)
	(arc
		(start 359.862882 -219.01658)
		(mid 359.580434 -218.940931)
		(end 359.297986 -219.01658)
		(width 0.0889)
		(layer "In6.Cu")
		(net "DMI_CPU0_PCH_RX_C_DP<3>")
	)
	(arc
		(start 360.701336 -218.20632)
		(mid 360.498749 -218.412671)
		(end 360.42473 -218.692222)
		(width 0.0889)
		(layer "In6.Cu")
		(net "DMI_CPU0_PCH_RX_C_DP<3>")
	)
	(arc
		(start 358.075484 -219.506038)
		(mid 358.027805 -219.688938)
		(end 357.896922 -219.825316)
		(width 0.0889)
		(layer "In6.Cu")
		(net "DMI_CPU0_PCH_RX_C_DP<3>")
	)
	(arc
		(start 357.87584 -221.465394)
		(mid 357.677612 -221.671242)
		(end 357.60533 -221.94774)
		(width 0.0889)
		(layer "In6.Cu")
		(net "DMI_CPU0_PCH_RX_C_DP<3>")
	)
	(arc
		(start 356.948232 -223.085914)
		(mid 356.744751 -223.286718)
		(end 356.66553 -223.561402)
		(width 0.0889)
		(layer "In6.Cu")
		(net "DMI_CPU0_PCH_RX_C_DP<3>")
	)
	(arc
		(start 361.36453 -217.071956)
		(mid 361.442159 -217.350369)
		(end 361.647232 -217.554048)
		(width 0.0889)
		(layer "In6.Cu")
		(net "DMI_CPU0_PCH_RX_C_DP<3>")
	)
	(arc
		(start 362.504228 -215.005412)
		(mid 362.358906 -215.194548)
		(end 362.304584 -215.426798)
		(width 0.0889)
		(layer "In6.Cu")
		(net "DMI_CPU0_PCH_RX_C_DP<3>")
	)
	(arc
		(start 358.357932 -219.01658)
		(mid 358.153597 -219.219185)
		(end 358.075484 -219.496132)
		(width 0.0889)
		(layer "In6.Cu")
		(net "DMI_CPU0_PCH_RX_C_DP<3>")
	)
	(arc
		(start 358.923336 -219.016834)
		(mid 358.646747 -218.941181)
		(end 358.3686 -219.010992)
		(width 0.0889)
		(layer "In6.Cu")
		(net "DMI_CPU0_PCH_RX_C_DP<3>")
	)
	(arc
		(start 358.075484 -221.140528)
		(mid 358.026231 -221.319728)
		(end 357.896922 -221.453202)
		(width 0.0889)
		(layer "In6.Cu")
		(net "DMI_CPU0_PCH_RX_C_DP<3>")
	)
	(arc
		(start 362.101384 -215.77046)
		(mid 361.905667 -215.975877)
		(end 361.83443 -216.25052)
		(width 0.0889)
		(layer "In6.Cu")
		(net "DMI_CPU0_PCH_RX_C_DP<3>")
	)
	(arc
		(start 356.195884 -226.017328)
		(mid 356.148205 -226.200228)
		(end 356.017322 -226.336606)
		(width 0.0889)
		(layer "In6.Cu")
		(net "DMI_CPU0_PCH_RX_C_DP<3>")
	)
	(arc
		(start 355.72573 -226.831144)
		(mid 355.678051 -227.014044)
		(end 355.547168 -227.150422)
		(width 0.0889)
		(layer "In6.Cu")
		(net "DMI_CPU0_PCH_RX_C_DP<3>")
	)
	(arc
		(start 356.195884 -224.404936)
		(mid 356.275254 -224.67867)
		(end 356.478078 -224.8789)
		(width 0.0889)
		(layer "In6.Cu")
		(net "DMI_CPU0_PCH_RX_C_DP<3>")
	)
	(arc
		(start 356.478332 -223.899984)
		(mid 356.273997 -224.102589)
		(end 356.195884 -224.379536)
		(width 0.0889)
		(layer "In6.Cu")
		(net "DMI_CPU0_PCH_RX_C_DP<3>")
	)
	(arc
		(start 361.272836 -218.202764)
		(mid 360.998637 -218.126929)
		(end 360.722164 -218.194128)
		(width 0.0889)
		(layer "In6.Cu")
		(net "DMI_CPU0_PCH_RX_C_DP<3>")
	)
	(arc
		(start 357.135684 -222.761556)
		(mid 357.088005 -222.944456)
		(end 356.957122 -223.080834)
		(width 0.0889)
		(layer "In6.Cu")
		(net "DMI_CPU0_PCH_RX_C_DP<3>")
	)
	(arc
		(start 362.304584 -215.44534)
		(mid 362.252314 -215.627705)
		(end 362.117386 -215.761062)
		(width 0.0889)
		(layer "In6.Cu")
		(net "DMI_CPU0_PCH_RX_C_DP<3>")
	)
	(arc
		(start 357.60533 -220.327474)
		(mid 357.682959 -220.605887)
		(end 357.888032 -220.809566)
		(width 0.0889)
		(layer "In6.Cu")
		(net "DMI_CPU0_PCH_RX_C_DP<3>")
	)
	(arc
		(start 357.896922 -220.814646)
		(mid 358.024815 -220.945708)
		(end 358.07523 -221.121732)
		(width 0.0889)
		(layer "In6.Cu")
		(net "DMI_CPU0_PCH_RX_C_DP<3>")
	)
	(arc
		(start 356.665276 -225.21799)
		(mid 356.614222 -225.39257)
		(end 356.486968 -225.522536)
		(width 0.0889)
		(layer "In6.Cu")
		(net "DMI_CPU0_PCH_RX_C_DP<3>")
	)
	(arc
		(start 361.640882 -216.578434)
		(mid 361.438469 -216.784847)
		(end 361.36453 -217.064336)
		(width 0.0889)
		(layer "In6.Cu")
		(net "DMI_CPU0_PCH_RX_C_DP<3>")
	)
	(arc
		(start 358.07523 -221.121732)
		(mid 358.075475 -221.131128)
		(end 358.075484 -221.140528)
		(width 0.0889)
		(layer "In6.Cu")
		(net "DMI_CPU0_PCH_RX_C_DP<3>")
	)
	(arc
		(start 357.87584 -219.837508)
		(mid 357.677612 -220.043356)
		(end 357.60533 -220.319854)
		(width 0.0889)
		(layer "In6.Cu")
		(net "DMI_CPU0_PCH_RX_C_DP<3>")
	)
	(arc
		(start 357.417878 -222.272098)
		(mid 357.215055 -222.472329)
		(end 357.135684 -222.746062)
		(width 0.0889)
		(layer "In6.Cu")
		(net "DMI_CPU0_PCH_RX_C_DP<3>")
	)
	(arc
		(start 360.42473 -218.692222)
		(mid 360.377051 -218.875122)
		(end 360.246168 -219.0115)
		(width 0.0889)
		(layer "In6.Cu")
		(net "DMI_CPU0_PCH_RX_C_DP<3>")
	)
	(arc
		(start 358.3686 -219.010992)
		(mid 358.363377 -219.013884)
		(end 358.358186 -219.016834)
		(width 0.0889)
		(layer "In6.Cu")
		(net "DMI_CPU0_PCH_RX_C_DP<3>")
	)
	(arc
		(start 355.99624 -226.348798)
		(mid 355.798012 -226.554646)
		(end 355.72573 -226.831144)
		(width 0.0889)
		(layer "In6.Cu")
		(net "DMI_CPU0_PCH_RX_C_DP<3>")
	)
	(arc
		(start 359.27538 -219.029534)
		(mid 359.104026 -219.070538)
		(end 358.934258 -219.023438)
		(width 0.0889)
		(layer "In6.Cu")
		(net "DMI_CPU0_PCH_RX_C_DP<3>")
	)
	(arc
		(start 357.60533 -221.94774)
		(mid 357.557651 -222.13064)
		(end 357.426768 -222.267018)
		(width 0.0889)
		(layer "In6.Cu")
		(net "DMI_CPU0_PCH_RX_C_DP<3>")
	)
	(arc
		(start 361.83443 -216.25052)
		(mid 361.786751 -216.43342)
		(end 361.655868 -216.569798)
		(width 0.0889)
		(layer "In6.Cu")
		(net "DMI_CPU0_PCH_RX_C_DP<3>")
	)
	(arc
		(start 356.66553 -225.203258)
		(mid 356.665478 -225.210625)
		(end 356.665276 -225.21799)
		(width 0.0889)
		(layer "In6.Cu")
		(net "DMI_CPU0_PCH_RX_C_DP<3>")
	)
	(arc
		(start 356.478078 -225.527616)
		(mid 356.276796 -225.725103)
		(end 356.195884 -225.99523)
		(width 0.0889)
		(layer "In6.Cu")
		(net "DMI_CPU0_PCH_RX_C_DP<3>")
	)
	(arc
		(start 360.237278 -219.01658)
		(mid 360.05008 -219.066723)
		(end 359.862882 -219.01658)
		(width 0.0889)
		(layer "In6.Cu")
		(net "DMI_CPU0_PCH_RX_C_DP<3>")
	)
	(segment
		(start 354.411534 -228.459284)
		(end 354.41128 -228.45903)
		(width 0.13208)
		(layer "F.Cu")
		(net "DMI_CPU0_PCH_RX_C_DP<2>")
	)
	(segment
		(start 354.411534 -228.99497)
		(end 354.411534 -228.459284)
		(width 0.13208)
		(layer "F.Cu")
		(net "DMI_CPU0_PCH_RX_C_DP<2>")
	)
	(segment
		(start 337.43392 -82.271108)
		(end 337.13166 -81.968848)
		(width 0.13208)
		(layer "B.Cu")
		(net "DMI_CPU0_PCH_RX_C_DP<2>")
	)
	(segment
		(start 340.543896 -70.283832)
		(end 341.63508 -67.649344)
		(width 0.13208)
		(layer "B.Cu")
		(net "DMI_CPU0_PCH_RX_C_DP<2>")
	)
	(segment
		(start 337.13166 -79.647542)
		(end 341.557356 -75.221846)
		(width 0.13208)
		(layer "B.Cu")
		(net "DMI_CPU0_PCH_RX_C_DP<2>")
	)
	(segment
		(start 337.13166 -81.968848)
		(end 337.13166 -79.647542)
		(width 0.13208)
		(layer "B.Cu")
		(net "DMI_CPU0_PCH_RX_C_DP<2>")
	)
	(segment
		(start 341.557356 -73.510394)
		(end 341.513668 -73.444862)
		(width 0.13208)
		(layer "B.Cu")
		(net "DMI_CPU0_PCH_RX_C_DP<2>")
	)
	(segment
		(start 341.63508 -67.649344)
		(end 341.63508 -65.726818)
		(width 0.13208)
		(layer "B.Cu")
		(net "DMI_CPU0_PCH_RX_C_DP<2>")
	)
	(segment
		(start 340.543896 -71.993252)
		(end 340.543896 -70.283832)
		(width 0.13208)
		(layer "B.Cu")
		(net "DMI_CPU0_PCH_RX_C_DP<2>")
	)
	(segment
		(start 341.513668 -73.444862)
		(end 341.513668 -73.445116)
		(width 0.13208)
		(layer "B.Cu")
		(net "DMI_CPU0_PCH_RX_C_DP<2>")
	)
	(segment
		(start 341.513668 -73.445116)
		(end 340.543896 -71.993252)
		(width 0.13208)
		(layer "B.Cu")
		(net "DMI_CPU0_PCH_RX_C_DP<2>")
	)
	(segment
		(start 341.63508 -65.726818)
		(end 341.233252 -64.756538)
		(width 0.13208)
		(layer "B.Cu")
		(net "DMI_CPU0_PCH_RX_C_DP<2>")
	)
	(segment
		(start 341.557356 -75.221846)
		(end 341.557356 -73.510394)
		(width 0.13208)
		(layer "B.Cu")
		(net "DMI_CPU0_PCH_RX_C_DP<2>")
	)
	(segment
		(start 341.233252 -63.438278)
		(end 340.992968 -63.197994)
		(width 0.13208)
		(layer "B.Cu")
		(net "DMI_CPU0_PCH_RX_C_DP<2>")
	)
	(segment
		(start 340.992968 -62.650624)
		(end 341.320628 -62.322964)
		(width 0.13208)
		(layer "B.Cu")
		(net "DMI_CPU0_PCH_RX_C_DP<2>")
	)
	(segment
		(start 341.233252 -64.756538)
		(end 341.233252 -63.438278)
		(width 0.13208)
		(layer "B.Cu")
		(net "DMI_CPU0_PCH_RX_C_DP<2>")
	)
	(segment
		(start 340.992968 -63.197994)
		(end 340.992968 -62.650624)
		(width 0.13208)
		(layer "B.Cu")
		(net "DMI_CPU0_PCH_RX_C_DP<2>")
	)
	(segment
		(start 354.506784 -227.659184)
		(end 354.506784 -227.64496)
		(width 0.0889)
		(layer "In6.Cu")
		(net "DMI_CPU0_PCH_RX_C_DP<2>")
	)
	(segment
		(start 362.205778 -213.223348)
		(end 362.205778 -212.674962)
		(width 0.0889)
		(layer "In6.Cu")
		(net "DMI_CPU0_PCH_RX_C_DP<2>")
	)
	(segment
		(start 354.976684 -226.84105)
		(end 354.976684 -226.822508)
		(width 0.0889)
		(layer "In6.Cu")
		(net "DMI_CPU0_PCH_RX_C_DP<2>")
	)
	(segment
		(start 362.207302 -213.224872)
		(end 362.205778 -213.223348)
		(width 0.0889)
		(layer "In6.Cu")
		(net "DMI_CPU0_PCH_RX_C_DP<2>")
	)
	(segment
		(start 354.41128 -228.45903)
		(end 354.254816 -228.188012)
		(width 0.0889)
		(layer "In6.Cu")
		(net "DMI_CPU0_PCH_RX_C_DP<2>")
	)
	(segment
		(start 377.921774 -186.673236)
		(end 379.793246 -176.068736)
		(width 0.14732)
		(layer "In6.Cu")
		(net "DMI_CPU0_PCH_RX_C_DP<2>")
	)
	(segment
		(start 370.775738 -195.146676)
		(end 370.775992 -195.146422)
		(width 0.14732)
		(layer "In6.Cu")
		(net "DMI_CPU0_PCH_RX_C_DP<2>")
	)
	(segment
		(start 357.513636 -219.18168)
		(end 357.519732 -219.178124)
		(width 0.0889)
		(layer "In6.Cu")
		(net "DMI_CPU0_PCH_RX_C_DP<2>")
	)
	(segment
		(start 337.793076 -87.542878)
		(end 337.13928 -85.088476)
		(width 0.14732)
		(layer "In6.Cu")
		(net "DMI_CPU0_PCH_RX_C_DP<2>")
	)
	(segment
		(start 357.044244 -219.994988)
		(end 357.049578 -219.99194)
		(width 0.0889)
		(layer "In6.Cu")
		(net "DMI_CPU0_PCH_RX_C_DP<2>")
	)
	(segment
		(start 356.095046 -223.256348)
		(end 356.103936 -223.251268)
		(width 0.0889)
		(layer "In6.Cu")
		(net "DMI_CPU0_PCH_RX_C_DP<2>")
	)
	(segment
		(start 379.793246 -176.068736)
		(end 376.240294 -155.933394)
		(width 0.14732)
		(layer "In6.Cu")
		(net "DMI_CPU0_PCH_RX_C_DP<2>")
	)
	(segment
		(start 358.357932 -218.367864)
		(end 358.368346 -218.37396)
		(width 0.0889)
		(layer "In6.Cu")
		(net "DMI_CPU0_PCH_RX_C_DP<2>")
	)
	(segment
		(start 357.044244 -221.622874)
		(end 357.049578 -221.619826)
		(width 0.0889)
		(layer "In6.Cu")
		(net "DMI_CPU0_PCH_RX_C_DP<2>")
	)
	(segment
		(start 356.856284 -220.32849)
		(end 356.856284 -220.311218)
		(width 0.0889)
		(layer "In6.Cu")
		(net "DMI_CPU0_PCH_RX_C_DP<2>")
	)
	(segment
		(start 355.163882 -226.506786)
		(end 355.164644 -226.506278)
		(width 0.0889)
		(layer "In6.Cu")
		(net "DMI_CPU0_PCH_RX_C_DP<2>")
	)
	(segment
		(start 362.247688 -212.633052)
		(end 362.247688 -212.610954)
		(width 0.0889)
		(layer "In6.Cu")
		(net "DMI_CPU0_PCH_RX_C_DP<2>")
	)
	(segment
		(start 355.625146 -225.69805)
		(end 355.634036 -225.69297)
		(width 0.0889)
		(layer "In6.Cu")
		(net "DMI_CPU0_PCH_RX_C_DP<2>")
	)
	(segment
		(start 355.91623 -225.225356)
		(end 355.91623 -225.187764)
		(width 0.0889)
		(layer "In6.Cu")
		(net "DMI_CPU0_PCH_RX_C_DP<2>")
	)
	(segment
		(start 358.075484 -217.878406)
		(end 358.075484 -217.888312)
		(width 0.0889)
		(layer "In6.Cu")
		(net "DMI_CPU0_PCH_RX_C_DP<2>")
	)
	(segment
		(start 356.386384 -222.780098)
		(end 356.386384 -222.761556)
		(width 0.0889)
		(layer "In6.Cu")
		(net "DMI_CPU0_PCH_RX_C_DP<2>")
	)
	(segment
		(start 355.634036 -224.7138)
		(end 355.625146 -224.70872)
		(width 0.0889)
		(layer "In6.Cu")
		(net "DMI_CPU0_PCH_RX_C_DP<2>")
	)
	(segment
		(start 357.041958 -221.624144)
		(end 357.043482 -221.623382)
		(width 0.0889)
		(layer "In6.Cu")
		(net "DMI_CPU0_PCH_RX_C_DP<2>")
	)
	(segment
		(start 356.564946 -222.442278)
		(end 356.573836 -222.437198)
		(width 0.0889)
		(layer "In6.Cu")
		(net "DMI_CPU0_PCH_RX_C_DP<2>")
	)
	(segment
		(start 368.475768 -196.75729)
		(end 370.775738 -195.146676)
		(width 0.14732)
		(layer "In6.Cu")
		(net "DMI_CPU0_PCH_RX_C_DP<2>")
	)
	(segment
		(start 338.446618 -89.99728)
		(end 337.793076 -87.543386)
		(width 0.14732)
		(layer "In6.Cu")
		(net "DMI_CPU0_PCH_RX_C_DP<2>")
	)
	(segment
		(start 361.263692 -215.931242)
		(end 361.272582 -215.926162)
		(width 0.0889)
		(layer "In6.Cu")
		(net "DMI_CPU0_PCH_RX_C_DP<2>")
	)
	(segment
		(start 357.043482 -219.995496)
		(end 357.044244 -219.994988)
		(width 0.0889)
		(layer "In6.Cu")
		(net "DMI_CPU0_PCH_RX_C_DP<2>")
	)
	(segment
		(start 361.08513 -216.260426)
		(end 361.08513 -216.25052)
		(width 0.0889)
		(layer "In6.Cu")
		(net "DMI_CPU0_PCH_RX_C_DP<2>")
	)
	(segment
		(start 376.240294 -155.933394)
		(end 338.446618 -89.99728)
		(width 0.14732)
		(layer "In6.Cu")
		(net "DMI_CPU0_PCH_RX_C_DP<2>")
	)
	(segment
		(start 362.205778 -212.674962)
		(end 362.247688 -212.633052)
		(width 0.0889)
		(layer "In6.Cu")
		(net "DMI_CPU0_PCH_RX_C_DP<2>")
	)
	(segment
		(start 337.13928 -85.088476)
		(end 337.13928 -82.565748)
		(width 0.14732)
		(layer "In6.Cu")
		(net "DMI_CPU0_PCH_RX_C_DP<2>")
	)
	(segment
		(start 357.034592 -221.628462)
		(end 357.041958 -221.624144)
		(width 0.0889)
		(layer "In6.Cu")
		(net "DMI_CPU0_PCH_RX_C_DP<2>")
	)
	(segment
		(start 357.888032 -217.554048)
		(end 357.896922 -217.559128)
		(width 0.0889)
		(layer "In6.Cu")
		(net "DMI_CPU0_PCH_RX_C_DP<2>")
	)
	(segment
		(start 357.043482 -221.623382)
		(end 357.044244 -221.622874)
		(width 0.0889)
		(layer "In6.Cu")
		(net "DMI_CPU0_PCH_RX_C_DP<2>")
	)
	(segment
		(start 337.13928 -82.565748)
		(end 337.43392 -82.271108)
		(width 0.14732)
		(layer "In6.Cu")
		(net "DMI_CPU0_PCH_RX_C_DP<2>")
	)
	(segment
		(start 362.207302 -214.674704)
		(end 362.207302 -213.224872)
		(width 0.0889)
		(layer "In6.Cu")
		(net "DMI_CPU0_PCH_RX_C_DP<2>")
	)
	(segment
		(start 359.384346 -217.559128)
		(end 359.393236 -217.554048)
		(width 0.0889)
		(layer "In6.Cu")
		(net "DMI_CPU0_PCH_RX_C_DP<2>")
	)
	(segment
		(start 357.519732 -218.20632)
		(end 357.513636 -218.202764)
		(width 0.0889)
		(layer "In6.Cu")
		(net "DMI_CPU0_PCH_RX_C_DP<2>")
	)
	(segment
		(start 355.625146 -224.070164)
		(end 355.634036 -224.065084)
		(width 0.0889)
		(layer "In6.Cu")
		(net "DMI_CPU0_PCH_RX_C_DP<2>")
	)
	(segment
		(start 357.326184 -221.133924)
		(end 357.326184 -221.1197)
		(width 0.0889)
		(layer "In6.Cu")
		(net "DMI_CPU0_PCH_RX_C_DP<2>")
	)
	(segment
		(start 357.513636 -218.202764)
		(end 357.504746 -218.197684)
		(width 0.0889)
		(layer "In6.Cu")
		(net "DMI_CPU0_PCH_RX_C_DP<2>")
	)
	(segment
		(start 362.247688 -212.610954)
		(end 362.247688 -209.428588)
		(width 0.14732)
		(layer "In6.Cu")
		(net "DMI_CPU0_PCH_RX_C_DP<2>")
	)
	(segment
		(start 361.55503 -215.44661)
		(end 361.55503 -215.436704)
		(width 0.0889)
		(layer "In6.Cu")
		(net "DMI_CPU0_PCH_RX_C_DP<2>")
	)
	(segment
		(start 355.164644 -226.506278)
		(end 355.169978 -226.50323)
		(width 0.0889)
		(layer "In6.Cu")
		(net "DMI_CPU0_PCH_RX_C_DP<2>")
	)
	(segment
		(start 354.254816 -228.188012)
		(end 354.278946 -228.098858)
		(width 0.0889)
		(layer "In6.Cu")
		(net "DMI_CPU0_PCH_RX_C_DP<2>")
	)
	(segment
		(start 355.634036 -224.065084)
		(end 355.640132 -224.061528)
		(width 0.0889)
		(layer "In6.Cu")
		(net "DMI_CPU0_PCH_RX_C_DP<2>")
	)
	(segment
		(start 337.793076 -87.543386)
		(end 337.793076 -87.542878)
		(width 0.14732)
		(layer "In6.Cu")
		(net "DMI_CPU0_PCH_RX_C_DP<2>")
	)
	(segment
		(start 356.85603 -221.963234)
		(end 356.85603 -221.94774)
		(width 0.0889)
		(layer "In6.Cu")
		(net "DMI_CPU0_PCH_RX_C_DP<2>")
	)
	(segment
		(start 363.13491 -204.384656)
		(end 368.475768 -196.75729)
		(width 0.14732)
		(layer "In6.Cu")
		(net "DMI_CPU0_PCH_RX_C_DP<2>")
	)
	(segment
		(start 373.155718 -193.479928)
		(end 377.921774 -186.673236)
		(width 0.14732)
		(layer "In6.Cu")
		(net "DMI_CPU0_PCH_RX_C_DP<2>")
	)
	(segment
		(start 361.733592 -215.117426)
		(end 361.742482 -215.112346)
		(width 0.0889)
		(layer "In6.Cu")
		(net "DMI_CPU0_PCH_RX_C_DP<2>")
	)
	(segment
		(start 357.504746 -219.18676)
		(end 357.513636 -219.18168)
		(width 0.0889)
		(layer "In6.Cu")
		(net "DMI_CPU0_PCH_RX_C_DP<2>")
	)
	(segment
		(start 360.615484 -217.082878)
		(end 360.615484 -217.0557)
		(width 0.0889)
		(layer "In6.Cu")
		(net "DMI_CPU0_PCH_RX_C_DP<2>")
	)
	(segment
		(start 361.859322 -215.022684)
		(end 362.207302 -214.674704)
		(width 0.0889)
		(layer "In6.Cu")
		(net "DMI_CPU0_PCH_RX_C_DP<2>")
	)
	(segment
		(start 354.685346 -227.325682)
		(end 354.694236 -227.320602)
		(width 0.0889)
		(layer "In6.Cu")
		(net "DMI_CPU0_PCH_RX_C_DP<2>")
	)
	(segment
		(start 359.205784 -217.8939)
		(end 359.205784 -217.878406)
		(width 0.0889)
		(layer "In6.Cu")
		(net "DMI_CPU0_PCH_RX_C_DP<2>")
	)
	(segment
		(start 362.247688 -209.428588)
		(end 363.13491 -204.384656)
		(width 0.14732)
		(layer "In6.Cu")
		(net "DMI_CPU0_PCH_RX_C_DP<2>")
	)
	(segment
		(start 357.504746 -217.559128)
		(end 357.513636 -217.554048)
		(width 0.0889)
		(layer "In6.Cu")
		(net "DMI_CPU0_PCH_RX_C_DP<2>")
	)
	(segment
		(start 370.775992 -195.146422)
		(end 373.155718 -193.479928)
		(width 0.14732)
		(layer "In6.Cu")
		(net "DMI_CPU0_PCH_RX_C_DP<2>")
	)
	(arc
		(start 356.856284 -220.311218)
		(mid 356.908554 -220.128853)
		(end 357.043482 -219.995496)
		(width 0.0889)
		(layer "In6.Cu")
		(net "DMI_CPU0_PCH_RX_C_DP<2>")
	)
	(arc
		(start 354.295964 -228.08565)
		(mid 354.448395 -227.895668)
		(end 354.506784 -227.659184)
		(width 0.0889)
		(layer "In6.Cu")
		(net "DMI_CPU0_PCH_RX_C_DP<2>")
	)
	(arc
		(start 354.694236 -227.320602)
		(mid 354.898571 -227.117997)
		(end 354.976684 -226.84105)
		(width 0.0889)
		(layer "In6.Cu")
		(net "DMI_CPU0_PCH_RX_C_DP<2>")
	)
	(arc
		(start 354.506784 -227.64496)
		(mid 354.554463 -227.46206)
		(end 354.685346 -227.325682)
		(width 0.0889)
		(layer "In6.Cu")
		(net "DMI_CPU0_PCH_RX_C_DP<2>")
	)
	(arc
		(start 357.326184 -217.878406)
		(mid 357.326236 -217.871039)
		(end 357.326438 -217.863674)
		(width 0.0889)
		(layer "In6.Cu")
		(net "DMI_CPU0_PCH_RX_C_DP<2>")
	)
	(arc
		(start 356.103936 -223.251268)
		(mid 356.306222 -223.052287)
		(end 356.386384 -222.780098)
		(width 0.0889)
		(layer "In6.Cu")
		(net "DMI_CPU0_PCH_RX_C_DP<2>")
	)
	(arc
		(start 355.916484 -223.575626)
		(mid 355.964163 -223.392726)
		(end 356.095046 -223.256348)
		(width 0.0889)
		(layer "In6.Cu")
		(net "DMI_CPU0_PCH_RX_C_DP<2>")
	)
	(arc
		(start 361.272582 -215.926162)
		(mid 361.476917 -215.723557)
		(end 361.55503 -215.44661)
		(width 0.0889)
		(layer "In6.Cu")
		(net "DMI_CPU0_PCH_RX_C_DP<2>")
	)
	(arc
		(start 358.92359 -218.367864)
		(mid 359.126413 -218.167633)
		(end 359.205784 -217.8939)
		(width 0.0889)
		(layer "In6.Cu")
		(net "DMI_CPU0_PCH_RX_C_DP<2>")
	)
	(arc
		(start 357.519732 -219.178124)
		(mid 357.796058 -218.692222)
		(end 357.519732 -218.20632)
		(width 0.0889)
		(layer "In6.Cu")
		(net "DMI_CPU0_PCH_RX_C_DP<2>")
	)
	(arc
		(start 359.767632 -217.554048)
		(mid 360.050334 -217.62979)
		(end 360.333036 -217.554048)
		(width 0.0889)
		(layer "In6.Cu")
		(net "DMI_CPU0_PCH_RX_C_DP<2>")
	)
	(arc
		(start 361.742482 -215.112346)
		(mid 361.80384 -215.071343)
		(end 361.859322 -215.022684)
		(width 0.0889)
		(layer "In6.Cu")
		(net "DMI_CPU0_PCH_RX_C_DP<2>")
	)
	(arc
		(start 355.634036 -225.69297)
		(mid 355.835318 -225.495483)
		(end 355.91623 -225.225356)
		(width 0.0889)
		(layer "In6.Cu")
		(net "DMI_CPU0_PCH_RX_C_DP<2>")
	)
	(arc
		(start 355.640132 -224.061528)
		(mid 355.842545 -223.855115)
		(end 355.916484 -223.575626)
		(width 0.0889)
		(layer "In6.Cu")
		(net "DMI_CPU0_PCH_RX_C_DP<2>")
	)
	(arc
		(start 359.205784 -217.878406)
		(mid 359.253463 -217.695506)
		(end 359.384346 -217.559128)
		(width 0.0889)
		(layer "In6.Cu")
		(net "DMI_CPU0_PCH_RX_C_DP<2>")
	)
	(arc
		(start 357.049578 -221.619826)
		(mid 357.252165 -221.413475)
		(end 357.326184 -221.133924)
		(width 0.0889)
		(layer "In6.Cu")
		(net "DMI_CPU0_PCH_RX_C_DP<2>")
	)
	(arc
		(start 359.393236 -217.554048)
		(mid 359.580434 -217.503905)
		(end 359.767632 -217.554048)
		(width 0.0889)
		(layer "In6.Cu")
		(net "DMI_CPU0_PCH_RX_C_DP<2>")
	)
	(arc
		(start 361.55503 -215.436704)
		(mid 361.602709 -215.253804)
		(end 361.733592 -215.117426)
		(width 0.0889)
		(layer "In6.Cu")
		(net "DMI_CPU0_PCH_RX_C_DP<2>")
	)
	(arc
		(start 357.043482 -220.644212)
		(mid 356.908549 -220.510858)
		(end 356.856284 -220.32849)
		(width 0.0889)
		(layer "In6.Cu")
		(net "DMI_CPU0_PCH_RX_C_DP<2>")
	)
	(arc
		(start 355.446838 -226.002596)
		(mid 355.497892 -225.828016)
		(end 355.625146 -225.69805)
		(width 0.0889)
		(layer "In6.Cu")
		(net "DMI_CPU0_PCH_RX_C_DP<2>")
	)
	(arc
		(start 361.08513 -216.25052)
		(mid 361.132809 -216.06762)
		(end 361.263692 -215.931242)
		(width 0.0889)
		(layer "In6.Cu")
		(net "DMI_CPU0_PCH_RX_C_DP<2>")
	)
	(arc
		(start 354.976684 -226.822508)
		(mid 355.028954 -226.640143)
		(end 355.163882 -226.506786)
		(width 0.0889)
		(layer "In6.Cu")
		(net "DMI_CPU0_PCH_RX_C_DP<2>")
	)
	(arc
		(start 356.573836 -222.437198)
		(mid 356.776659 -222.236967)
		(end 356.85603 -221.963234)
		(width 0.0889)
		(layer "In6.Cu")
		(net "DMI_CPU0_PCH_RX_C_DP<2>")
	)
	(arc
		(start 357.326438 -217.863674)
		(mid 357.377492 -217.689094)
		(end 357.504746 -217.559128)
		(width 0.0889)
		(layer "In6.Cu")
		(net "DMI_CPU0_PCH_RX_C_DP<2>")
	)
	(arc
		(start 355.91623 -225.187764)
		(mid 355.83686 -224.91403)
		(end 355.634036 -224.7138)
		(width 0.0889)
		(layer "In6.Cu")
		(net "DMI_CPU0_PCH_RX_C_DP<2>")
	)
	(arc
		(start 360.615484 -217.0557)
		(mid 360.667754 -216.873335)
		(end 360.802682 -216.739978)
		(width 0.0889)
		(layer "In6.Cu")
		(net "DMI_CPU0_PCH_RX_C_DP<2>")
	)
	(arc
		(start 357.326184 -221.1197)
		(mid 357.246965 -220.845015)
		(end 357.043482 -220.644212)
		(width 0.0889)
		(layer "In6.Cu")
		(net "DMI_CPU0_PCH_RX_C_DP<2>")
	)
	(arc
		(start 355.169978 -226.50323)
		(mid 355.372565 -226.296879)
		(end 355.446584 -226.017328)
		(width 0.0889)
		(layer "In6.Cu")
		(net "DMI_CPU0_PCH_RX_C_DP<2>")
	)
	(arc
		(start 357.896922 -217.559128)
		(mid 358.027836 -217.695488)
		(end 358.075484 -217.878406)
		(width 0.0889)
		(layer "In6.Cu")
		(net "DMI_CPU0_PCH_RX_C_DP<2>")
	)
	(arc
		(start 357.049578 -219.99194)
		(mid 357.252165 -219.785589)
		(end 357.326184 -219.506038)
		(width 0.0889)
		(layer "In6.Cu")
		(net "DMI_CPU0_PCH_RX_C_DP<2>")
	)
	(arc
		(start 357.504746 -218.197684)
		(mid 357.373832 -218.061324)
		(end 357.326184 -217.878406)
		(width 0.0889)
		(layer "In6.Cu")
		(net "DMI_CPU0_PCH_RX_C_DP<2>")
	)
	(arc
		(start 358.075484 -217.888312)
		(mid 358.153595 -218.165261)
		(end 358.357932 -218.367864)
		(width 0.0889)
		(layer "In6.Cu")
		(net "DMI_CPU0_PCH_RX_C_DP<2>")
	)
	(arc
		(start 360.333036 -217.554048)
		(mid 360.535322 -217.355067)
		(end 360.615484 -217.082878)
		(width 0.0889)
		(layer "In6.Cu")
		(net "DMI_CPU0_PCH_RX_C_DP<2>")
	)
	(arc
		(start 360.802682 -216.739978)
		(mid 361.007017 -216.537373)
		(end 361.08513 -216.260426)
		(width 0.0889)
		(layer "In6.Cu")
		(net "DMI_CPU0_PCH_RX_C_DP<2>")
	)
	(arc
		(start 356.386384 -222.761556)
		(mid 356.434063 -222.578656)
		(end 356.564946 -222.442278)
		(width 0.0889)
		(layer "In6.Cu")
		(net "DMI_CPU0_PCH_RX_C_DP<2>")
	)
	(arc
		(start 355.625146 -224.70872)
		(mid 355.44667 -224.389442)
		(end 355.625146 -224.070164)
		(width 0.0889)
		(layer "In6.Cu")
		(net "DMI_CPU0_PCH_RX_C_DP<2>")
	)
	(arc
		(start 355.446584 -226.017328)
		(mid 355.446636 -226.009961)
		(end 355.446838 -226.002596)
		(width 0.0889)
		(layer "In6.Cu")
		(net "DMI_CPU0_PCH_RX_C_DP<2>")
	)
	(arc
		(start 357.326184 -219.506038)
		(mid 357.373863 -219.323138)
		(end 357.504746 -219.18676)
		(width 0.0889)
		(layer "In6.Cu")
		(net "DMI_CPU0_PCH_RX_C_DP<2>")
	)
	(arc
		(start 357.513636 -217.554048)
		(mid 357.700834 -217.503905)
		(end 357.888032 -217.554048)
		(width 0.0889)
		(layer "In6.Cu")
		(net "DMI_CPU0_PCH_RX_C_DP<2>")
	)
	(arc
		(start 356.85603 -221.94774)
		(mid 356.903709 -221.76484)
		(end 357.034592 -221.628462)
		(width 0.0889)
		(layer "In6.Cu")
		(net "DMI_CPU0_PCH_RX_C_DP<2>")
	)
	(arc
		(start 354.278946 -228.098858)
		(mid 354.287518 -228.092335)
		(end 354.295964 -228.08565)
		(width 0.0889)
		(layer "In6.Cu")
		(net "DMI_CPU0_PCH_RX_C_DP<2>")
	)
	(arc
		(start 358.368346 -218.37396)
		(mid 358.646778 -218.443806)
		(end 358.92359 -218.367864)
		(width 0.0889)
		(layer "In6.Cu")
		(net "DMI_CPU0_PCH_RX_C_DP<2>")
	)
	(segment
		(start 353.471734 -227.367084)
		(end 353.471734 -226.831398)
		(width 0.13208)
		(layer "F.Cu")
		(net "DMI_CPU0_PCH_RX_C_DP<1>")
	)
	(segment
		(start 353.471734 -226.831398)
		(end 353.47148 -226.831144)
		(width 0.13208)
		(layer "F.Cu")
		(net "DMI_CPU0_PCH_RX_C_DP<1>")
	)
	(segment
		(start 334.621632 -79.617062)
		(end 338.261452 -75.977242)
		(width 0.13208)
		(layer "B.Cu")
		(net "DMI_CPU0_PCH_RX_C_DP<1>")
	)
	(segment
		(start 339.77072 -67.762628)
		(end 339.77072 -67.019424)
		(width 0.13208)
		(layer "B.Cu")
		(net "DMI_CPU0_PCH_RX_C_DP<1>")
	)
	(segment
		(start 339.124036 -69.323966)
		(end 339.77072 -67.762628)
		(width 0.13208)
		(layer "B.Cu")
		(net "DMI_CPU0_PCH_RX_C_DP<1>")
	)
	(segment
		(start 339.77072 -67.019424)
		(end 339.44306 -66.691764)
		(width 0.13208)
		(layer "B.Cu")
		(net "DMI_CPU0_PCH_RX_C_DP<1>")
	)
	(segment
		(start 339.124036 -71.499476)
		(end 339.124036 -69.323966)
		(width 0.13208)
		(layer "B.Cu")
		(net "DMI_CPU0_PCH_RX_C_DP<1>")
	)
	(segment
		(start 338.295742 -73.498964)
		(end 339.124036 -71.499476)
		(width 0.13208)
		(layer "B.Cu")
		(net "DMI_CPU0_PCH_RX_C_DP<1>")
	)
	(segment
		(start 338.298028 -73.501758)
		(end 338.295742 -73.498964)
		(width 0.13208)
		(layer "B.Cu")
		(net "DMI_CPU0_PCH_RX_C_DP<1>")
	)
	(segment
		(start 338.261452 -75.977242)
		(end 338.261452 -73.685146)
		(width 0.13208)
		(layer "B.Cu")
		(net "DMI_CPU0_PCH_RX_C_DP<1>")
	)
	(segment
		(start 334.621632 -80.488282)
		(end 334.621632 -79.617062)
		(width 0.13208)
		(layer "B.Cu")
		(net "DMI_CPU0_PCH_RX_C_DP<1>")
	)
	(segment
		(start 334.319372 -80.790542)
		(end 334.621632 -80.488282)
		(width 0.13208)
		(layer "B.Cu")
		(net "DMI_CPU0_PCH_RX_C_DP<1>")
	)
	(segment
		(start 338.261452 -73.685146)
		(end 338.298028 -73.501758)
		(width 0.13208)
		(layer "B.Cu")
		(net "DMI_CPU0_PCH_RX_C_DP<1>")
	)
	(segment
		(start 334.614012 -83.784694)
		(end 334.73898 -84.242656)
		(width 0.14732)
		(layer "In6.Cu")
		(net "DMI_CPU0_PCH_RX_C_DP<1>")
	)
	(segment
		(start 361.005628 -214.079836)
		(end 361.104688 -214.178896)
		(width 0.0889)
		(layer "In6.Cu")
		(net "DMI_CPU0_PCH_RX_C_DP<1>")
	)
	(segment
		(start 378.577094 -175.996346)
		(end 376.737118 -186.419236)
		(width 0.14732)
		(layer "In6.Cu")
		(net "DMI_CPU0_PCH_RX_C_DP<1>")
	)
	(segment
		(start 361.104688 -212.1281)
		(end 361.104688 -212.263736)
		(width 0.0889)
		(layer "In6.Cu")
		(net "DMI_CPU0_PCH_RX_C_DP<1>")
	)
	(segment
		(start 353.336098 -227.18014)
		(end 353.315016 -227.102162)
		(width 0.0889)
		(layer "In6.Cu")
		(net "DMI_CPU0_PCH_RX_C_DP<1>")
	)
	(segment
		(start 336.757264 -91.642184)
		(end 375.20245 -156.875734)
		(width 0.14732)
		(layer "In6.Cu")
		(net "DMI_CPU0_PCH_RX_C_DP<1>")
	)
	(segment
		(start 361.005628 -213.089236)
		(end 361.005628 -213.353396)
		(width 0.0889)
		(layer "In6.Cu")
		(net "DMI_CPU0_PCH_RX_C_DP<1>")
	)
	(segment
		(start 356.008432 -219.830396)
		(end 355.99624 -219.837508)
		(width 0.0889)
		(layer "In6.Cu")
		(net "DMI_CPU0_PCH_RX_C_DP<1>")
	)
	(segment
		(start 354.607368 -225.522536)
		(end 354.598478 -225.527616)
		(width 0.0889)
		(layer "In6.Cu")
		(net "DMI_CPU0_PCH_RX_C_DP<1>")
	)
	(segment
		(start 356.478078 -218.367864)
		(end 356.486968 -218.372944)
		(width 0.0889)
		(layer "In6.Cu")
		(net "DMI_CPU0_PCH_RX_C_DP<1>")
	)
	(segment
		(start 354.128832 -226.341686)
		(end 354.11664 -226.348798)
		(width 0.0889)
		(layer "In6.Cu")
		(net "DMI_CPU0_PCH_RX_C_DP<1>")
	)
	(segment
		(start 360.246168 -215.755982)
		(end 360.237278 -215.761062)
		(width 0.0889)
		(layer "In6.Cu")
		(net "DMI_CPU0_PCH_RX_C_DP<1>")
	)
	(segment
		(start 364.821978 -199.90816)
		(end 362.012738 -203.919836)
		(width 0.14732)
		(layer "In6.Cu")
		(net "DMI_CPU0_PCH_RX_C_DP<1>")
	)
	(segment
		(start 361.062524 -212.085936)
		(end 361.104688 -212.1281)
		(width 0.0889)
		(layer "In6.Cu")
		(net "DMI_CPU0_PCH_RX_C_DP<1>")
	)
	(segment
		(start 361.062524 -212.063838)
		(end 361.062524 -212.085936)
		(width 0.0889)
		(layer "In6.Cu")
		(net "DMI_CPU0_PCH_RX_C_DP<1>")
	)
	(segment
		(start 334.614012 -81.085182)
		(end 334.614012 -83.784694)
		(width 0.14732)
		(layer "In6.Cu")
		(net "DMI_CPU0_PCH_RX_C_DP<1>")
	)
	(segment
		(start 356.00767 -221.45879)
		(end 356.002336 -221.461838)
		(width 0.0889)
		(layer "In6.Cu")
		(net "DMI_CPU0_PCH_RX_C_DP<1>")
	)
	(segment
		(start 361.104688 -212.263736)
		(end 361.005628 -212.362796)
		(width 0.0889)
		(layer "In6.Cu")
		(net "DMI_CPU0_PCH_RX_C_DP<1>")
	)
	(segment
		(start 361.062524 -209.324448)
		(end 361.062524 -212.063838)
		(width 0.14732)
		(layer "In6.Cu")
		(net "DMI_CPU0_PCH_RX_C_DP<1>")
	)
	(segment
		(start 354.78593 -223.561402)
		(end 354.78593 -223.584262)
		(width 0.0889)
		(layer "In6.Cu")
		(net "DMI_CPU0_PCH_RX_C_DP<1>")
	)
	(segment
		(start 356.009956 -221.45752)
		(end 356.008432 -221.458282)
		(width 0.0889)
		(layer "In6.Cu")
		(net "DMI_CPU0_PCH_RX_C_DP<1>")
	)
	(segment
		(start 361.104688 -213.452456)
		(end 361.104688 -213.716616)
		(width 0.0889)
		(layer "In6.Cu")
		(net "DMI_CPU0_PCH_RX_C_DP<1>")
	)
	(segment
		(start 355.547168 -222.267018)
		(end 355.538278 -222.272098)
		(width 0.0889)
		(layer "In6.Cu")
		(net "DMI_CPU0_PCH_RX_C_DP<1>")
	)
	(segment
		(start 361.005628 -212.362796)
		(end 361.005628 -212.626956)
		(width 0.0889)
		(layer "In6.Cu")
		(net "DMI_CPU0_PCH_RX_C_DP<1>")
	)
	(segment
		(start 375.20245 -156.875734)
		(end 378.577094 -175.996346)
		(width 0.14732)
		(layer "In6.Cu")
		(net "DMI_CPU0_PCH_RX_C_DP<1>")
	)
	(segment
		(start 353.315016 -227.102162)
		(end 353.47148 -226.831144)
		(width 0.0889)
		(layer "In6.Cu")
		(net "DMI_CPU0_PCH_RX_C_DP<1>")
	)
	(segment
		(start 334.644492 -84.40801)
		(end 334.739234 -84.756244)
		(width 0.14732)
		(layer "In6.Cu")
		(net "DMI_CPU0_PCH_RX_C_DP<1>")
	)
	(segment
		(start 353.667568 -227.150422)
		(end 353.659694 -227.154994)
		(width 0.0889)
		(layer "In6.Cu")
		(net "DMI_CPU0_PCH_RX_C_DP<1>")
	)
	(segment
		(start 364.822232 -199.907906)
		(end 364.821978 -199.90816)
		(width 0.14732)
		(layer "In6.Cu")
		(net "DMI_CPU0_PCH_RX_C_DP<1>")
	)
	(segment
		(start 334.904588 -84.850732)
		(end 336.757264 -91.642184)
		(width 0.14732)
		(layer "In6.Cu")
		(net "DMI_CPU0_PCH_RX_C_DP<1>")
	)
	(segment
		(start 334.73898 -84.242656)
		(end 334.644492 -84.40801)
		(width 0.14732)
		(layer "In6.Cu")
		(net "DMI_CPU0_PCH_RX_C_DP<1>")
	)
	(segment
		(start 355.077522 -223.080834)
		(end 355.068632 -223.085914)
		(width 0.0889)
		(layer "In6.Cu")
		(net "DMI_CPU0_PCH_RX_C_DP<1>")
	)
	(segment
		(start 356.008432 -221.458282)
		(end 356.00767 -221.45879)
		(width 0.0889)
		(layer "In6.Cu")
		(net "DMI_CPU0_PCH_RX_C_DP<1>")
	)
	(segment
		(start 362.012738 -203.919836)
		(end 361.062524 -209.324448)
		(width 0.14732)
		(layer "In6.Cu")
		(net "DMI_CPU0_PCH_RX_C_DP<1>")
	)
	(segment
		(start 334.319372 -80.790542)
		(end 334.614012 -81.085182)
		(width 0.14732)
		(layer "In6.Cu")
		(net "DMI_CPU0_PCH_RX_C_DP<1>")
	)
	(segment
		(start 361.104688 -212.990176)
		(end 361.005628 -213.089236)
		(width 0.0889)
		(layer "In6.Cu")
		(net "DMI_CPU0_PCH_RX_C_DP<1>")
	)
	(segment
		(start 361.005628 -213.815676)
		(end 361.005628 -214.079836)
		(width 0.0889)
		(layer "In6.Cu")
		(net "DMI_CPU0_PCH_RX_C_DP<1>")
	)
	(segment
		(start 356.008432 -220.809566)
		(end 356.009194 -220.810074)
		(width 0.0889)
		(layer "In6.Cu")
		(net "DMI_CPU0_PCH_RX_C_DP<1>")
	)
	(segment
		(start 356.195884 -217.859864)
		(end 356.195884 -217.8939)
		(width 0.0889)
		(layer "In6.Cu")
		(net "DMI_CPU0_PCH_RX_C_DP<1>")
	)
	(segment
		(start 361.104688 -212.726016)
		(end 361.104688 -212.990176)
		(width 0.0889)
		(layer "In6.Cu")
		(net "DMI_CPU0_PCH_RX_C_DP<1>")
	)
	(segment
		(start 359.95483 -216.240614)
		(end 359.95483 -216.259156)
		(width 0.0889)
		(layer "In6.Cu")
		(net "DMI_CPU0_PCH_RX_C_DP<1>")
	)
	(segment
		(start 356.017322 -219.825316)
		(end 356.008432 -219.830396)
		(width 0.0889)
		(layer "In6.Cu")
		(net "DMI_CPU0_PCH_RX_C_DP<1>")
	)
	(segment
		(start 372.470934 -192.512442)
		(end 367.624614 -195.905882)
		(width 0.14732)
		(layer "In6.Cu")
		(net "DMI_CPU0_PCH_RX_C_DP<1>")
	)
	(segment
		(start 334.739234 -84.756244)
		(end 334.904842 -84.850732)
		(width 0.14732)
		(layer "In6.Cu")
		(net "DMI_CPU0_PCH_RX_C_DP<1>")
	)
	(segment
		(start 361.057698 -214.587074)
		(end 360.737912 -214.90686)
		(width 0.0889)
		(layer "In6.Cu")
		(net "DMI_CPU0_PCH_RX_C_DP<1>")
	)
	(segment
		(start 356.195884 -219.490544)
		(end 356.195884 -219.506038)
		(width 0.0889)
		(layer "In6.Cu")
		(net "DMI_CPU0_PCH_RX_C_DP<1>")
	)
	(segment
		(start 353.659694 -227.154994)
		(end 353.658678 -227.155502)
		(width 0.0889)
		(layer "In6.Cu")
		(net "DMI_CPU0_PCH_RX_C_DP<1>")
	)
	(segment
		(start 356.017322 -221.453202)
		(end 356.009956 -221.45752)
		(width 0.0889)
		(layer "In6.Cu")
		(net "DMI_CPU0_PCH_RX_C_DP<1>")
	)
	(segment
		(start 361.005628 -213.353396)
		(end 361.104688 -213.452456)
		(width 0.0889)
		(layer "In6.Cu")
		(net "DMI_CPU0_PCH_RX_C_DP<1>")
	)
	(segment
		(start 361.104688 -213.716616)
		(end 361.005628 -213.815676)
		(width 0.0889)
		(layer "In6.Cu")
		(net "DMI_CPU0_PCH_RX_C_DP<1>")
	)
	(segment
		(start 356.962964 -216.566242)
		(end 356.948232 -216.574878)
		(width 0.0889)
		(layer "In6.Cu")
		(net "DMI_CPU0_PCH_RX_C_DP<1>")
	)
	(segment
		(start 356.009194 -220.810074)
		(end 356.017322 -220.814646)
		(width 0.0889)
		(layer "In6.Cu")
		(net "DMI_CPU0_PCH_RX_C_DP<1>")
	)
	(segment
		(start 356.66553 -217.064336)
		(end 356.66553 -217.072972)
		(width 0.0889)
		(layer "In6.Cu")
		(net "DMI_CPU0_PCH_RX_C_DP<1>")
	)
	(segment
		(start 367.624614 -195.905882)
		(end 364.822232 -199.907906)
		(width 0.14732)
		(layer "In6.Cu")
		(net "DMI_CPU0_PCH_RX_C_DP<1>")
	)
	(segment
		(start 356.948232 -216.574878)
		(end 356.942136 -216.578434)
		(width 0.0889)
		(layer "In6.Cu")
		(net "DMI_CPU0_PCH_RX_C_DP<1>")
	)
	(segment
		(start 354.598478 -224.8789)
		(end 354.607368 -224.88398)
		(width 0.0889)
		(layer "In6.Cu")
		(net "DMI_CPU0_PCH_RX_C_DP<1>")
	)
	(segment
		(start 334.904842 -84.850732)
		(end 334.904588 -84.850732)
		(width 0.14732)
		(layer "In6.Cu")
		(net "DMI_CPU0_PCH_RX_C_DP<1>")
	)
	(segment
		(start 355.72573 -220.319854)
		(end 355.72573 -220.327474)
		(width 0.0889)
		(layer "In6.Cu")
		(net "DMI_CPU0_PCH_RX_C_DP<1>")
	)
	(segment
		(start 354.316284 -225.99523)
		(end 354.316284 -226.017328)
		(width 0.0889)
		(layer "In6.Cu")
		(net "DMI_CPU0_PCH_RX_C_DP<1>")
	)
	(segment
		(start 361.104688 -214.178896)
		(end 361.104688 -214.473536)
		(width 0.0889)
		(layer "In6.Cu")
		(net "DMI_CPU0_PCH_RX_C_DP<1>")
	)
	(segment
		(start 376.737118 -186.419236)
		(end 372.470934 -192.512442)
		(width 0.14732)
		(layer "In6.Cu")
		(net "DMI_CPU0_PCH_RX_C_DP<1>")
	)
	(segment
		(start 355.256084 -222.746062)
		(end 355.256084 -222.761556)
		(width 0.0889)
		(layer "In6.Cu")
		(net "DMI_CPU0_PCH_RX_C_DP<1>")
	)
	(segment
		(start 356.486968 -219.0115)
		(end 356.478078 -219.01658)
		(width 0.0889)
		(layer "In6.Cu")
		(net "DMI_CPU0_PCH_RX_C_DP<1>")
	)
	(segment
		(start 354.316284 -224.379536)
		(end 354.316284 -224.404936)
		(width 0.0889)
		(layer "In6.Cu")
		(net "DMI_CPU0_PCH_RX_C_DP<1>")
	)
	(segment
		(start 354.137722 -226.336606)
		(end 354.128832 -226.341686)
		(width 0.0889)
		(layer "In6.Cu")
		(net "DMI_CPU0_PCH_RX_C_DP<1>")
	)
	(segment
		(start 361.005628 -212.626956)
		(end 361.104688 -212.726016)
		(width 0.0889)
		(layer "In6.Cu")
		(net "DMI_CPU0_PCH_RX_C_DP<1>")
	)
	(arc
		(start 356.478078 -219.01658)
		(mid 356.275255 -219.216811)
		(end 356.195884 -219.490544)
		(width 0.0889)
		(layer "In6.Cu")
		(net "DMI_CPU0_PCH_RX_C_DP<1>")
	)
	(arc
		(start 357.513636 -216.574878)
		(mid 357.239437 -216.499043)
		(end 356.962964 -216.566242)
		(width 0.0889)
		(layer "In6.Cu")
		(net "DMI_CPU0_PCH_RX_C_DP<1>")
	)
	(arc
		(start 359.95483 -216.259156)
		(mid 359.90256 -216.441521)
		(end 359.767632 -216.574878)
		(width 0.0889)
		(layer "In6.Cu")
		(net "DMI_CPU0_PCH_RX_C_DP<1>")
	)
	(arc
		(start 358.453436 -216.574878)
		(mid 358.170734 -216.499102)
		(end 357.888032 -216.574878)
		(width 0.0889)
		(layer "In6.Cu")
		(net "DMI_CPU0_PCH_RX_C_DP<1>")
	)
	(arc
		(start 356.195884 -219.506038)
		(mid 356.148205 -219.688938)
		(end 356.017322 -219.825316)
		(width 0.0889)
		(layer "In6.Cu")
		(net "DMI_CPU0_PCH_RX_C_DP<1>")
	)
	(arc
		(start 356.942136 -216.578434)
		(mid 356.739549 -216.784785)
		(end 356.66553 -217.064336)
		(width 0.0889)
		(layer "In6.Cu")
		(net "DMI_CPU0_PCH_RX_C_DP<1>")
	)
	(arc
		(start 355.72573 -221.94774)
		(mid 355.678051 -222.13064)
		(end 355.547168 -222.267018)
		(width 0.0889)
		(layer "In6.Cu")
		(net "DMI_CPU0_PCH_RX_C_DP<1>")
	)
	(arc
		(start 358.827832 -216.574878)
		(mid 358.640634 -216.625021)
		(end 358.453436 -216.574878)
		(width 0.0889)
		(layer "In6.Cu")
		(net "DMI_CPU0_PCH_RX_C_DP<1>")
	)
	(arc
		(start 354.316284 -224.404936)
		(mid 354.395654 -224.67867)
		(end 354.598478 -224.8789)
		(width 0.0889)
		(layer "In6.Cu")
		(net "DMI_CPU0_PCH_RX_C_DP<1>")
	)
	(arc
		(start 360.42473 -215.436704)
		(mid 360.377051 -215.619604)
		(end 360.246168 -215.755982)
		(width 0.0889)
		(layer "In6.Cu")
		(net "DMI_CPU0_PCH_RX_C_DP<1>")
	)
	(arc
		(start 356.002336 -221.461838)
		(mid 355.799749 -221.668189)
		(end 355.72573 -221.94774)
		(width 0.0889)
		(layer "In6.Cu")
		(net "DMI_CPU0_PCH_RX_C_DP<1>")
	)
	(arc
		(start 356.017322 -220.814646)
		(mid 356.195798 -221.133924)
		(end 356.017322 -221.453202)
		(width 0.0889)
		(layer "In6.Cu")
		(net "DMI_CPU0_PCH_RX_C_DP<1>")
	)
	(arc
		(start 354.78593 -225.203258)
		(mid 354.785878 -225.210625)
		(end 354.785676 -225.21799)
		(width 0.0889)
		(layer "In6.Cu")
		(net "DMI_CPU0_PCH_RX_C_DP<1>")
	)
	(arc
		(start 361.104688 -214.473536)
		(mid 361.092484 -214.534982)
		(end 361.057698 -214.587074)
		(width 0.0889)
		(layer "In6.Cu")
		(net "DMI_CPU0_PCH_RX_C_DP<1>")
	)
	(arc
		(start 355.72573 -220.327474)
		(mid 355.803359 -220.605887)
		(end 356.008432 -220.809566)
		(width 0.0889)
		(layer "In6.Cu")
		(net "DMI_CPU0_PCH_RX_C_DP<1>")
	)
	(arc
		(start 356.478332 -217.388694)
		(mid 356.276046 -217.587675)
		(end 356.195884 -217.859864)
		(width 0.0889)
		(layer "In6.Cu")
		(net "DMI_CPU0_PCH_RX_C_DP<1>")
	)
	(arc
		(start 355.99624 -219.837508)
		(mid 355.798012 -220.043356)
		(end 355.72573 -220.319854)
		(width 0.0889)
		(layer "In6.Cu")
		(net "DMI_CPU0_PCH_RX_C_DP<1>")
	)
	(arc
		(start 354.598478 -225.527616)
		(mid 354.397196 -225.725103)
		(end 354.316284 -225.99523)
		(width 0.0889)
		(layer "In6.Cu")
		(net "DMI_CPU0_PCH_RX_C_DP<1>")
	)
	(arc
		(start 354.11664 -226.348798)
		(mid 353.918412 -226.554646)
		(end 353.84613 -226.831144)
		(width 0.0889)
		(layer "In6.Cu")
		(net "DMI_CPU0_PCH_RX_C_DP<1>")
	)
	(arc
		(start 354.316284 -226.017328)
		(mid 354.268605 -226.200228)
		(end 354.137722 -226.336606)
		(width 0.0889)
		(layer "In6.Cu")
		(net "DMI_CPU0_PCH_RX_C_DP<1>")
	)
	(arc
		(start 360.237278 -215.761062)
		(mid 360.032943 -215.963667)
		(end 359.95483 -216.240614)
		(width 0.0889)
		(layer "In6.Cu")
		(net "DMI_CPU0_PCH_RX_C_DP<1>")
	)
	(arc
		(start 355.256084 -222.761556)
		(mid 355.208405 -222.944456)
		(end 355.077522 -223.080834)
		(width 0.0889)
		(layer "In6.Cu")
		(net "DMI_CPU0_PCH_RX_C_DP<1>")
	)
	(arc
		(start 354.598732 -223.899984)
		(mid 354.394397 -224.102589)
		(end 354.316284 -224.379536)
		(width 0.0889)
		(layer "In6.Cu")
		(net "DMI_CPU0_PCH_RX_C_DP<1>")
	)
	(arc
		(start 356.66553 -217.072972)
		(mid 356.61326 -217.255337)
		(end 356.478332 -217.388694)
		(width 0.0889)
		(layer "In6.Cu")
		(net "DMI_CPU0_PCH_RX_C_DP<1>")
	)
	(arc
		(start 354.785676 -225.21799)
		(mid 354.734622 -225.39257)
		(end 354.607368 -225.522536)
		(width 0.0889)
		(layer "In6.Cu")
		(net "DMI_CPU0_PCH_RX_C_DP<1>")
	)
	(arc
		(start 360.642916 -214.990426)
		(mid 360.48219 -215.188313)
		(end 360.42473 -215.436704)
		(width 0.0889)
		(layer "In6.Cu")
		(net "DMI_CPU0_PCH_RX_C_DP<1>")
	)
	(arc
		(start 354.607368 -224.88398)
		(mid 354.738282 -225.02034)
		(end 354.78593 -225.203258)
		(width 0.0889)
		(layer "In6.Cu")
		(net "DMI_CPU0_PCH_RX_C_DP<1>")
	)
	(arc
		(start 356.195884 -217.8939)
		(mid 356.275254 -218.167634)
		(end 356.478078 -218.367864)
		(width 0.0889)
		(layer "In6.Cu")
		(net "DMI_CPU0_PCH_RX_C_DP<1>")
	)
	(arc
		(start 359.767632 -216.574878)
		(mid 359.580434 -216.625021)
		(end 359.393236 -216.574878)
		(width 0.0889)
		(layer "In6.Cu")
		(net "DMI_CPU0_PCH_RX_C_DP<1>")
	)
	(arc
		(start 353.84613 -226.831144)
		(mid 353.798451 -227.014044)
		(end 353.667568 -227.150422)
		(width 0.0889)
		(layer "In6.Cu")
		(net "DMI_CPU0_PCH_RX_C_DP<1>")
	)
	(arc
		(start 355.538278 -222.272098)
		(mid 355.335455 -222.472329)
		(end 355.256084 -222.746062)
		(width 0.0889)
		(layer "In6.Cu")
		(net "DMI_CPU0_PCH_RX_C_DP<1>")
	)
	(arc
		(start 357.888032 -216.574878)
		(mid 357.700834 -216.625021)
		(end 357.513636 -216.574878)
		(width 0.0889)
		(layer "In6.Cu")
		(net "DMI_CPU0_PCH_RX_C_DP<1>")
	)
	(arc
		(start 355.068632 -223.085914)
		(mid 354.865151 -223.286718)
		(end 354.78593 -223.561402)
		(width 0.0889)
		(layer "In6.Cu")
		(net "DMI_CPU0_PCH_RX_C_DP<1>")
	)
	(arc
		(start 360.737912 -214.90686)
		(mid 360.691718 -214.950125)
		(end 360.642916 -214.990426)
		(width 0.0889)
		(layer "In6.Cu")
		(net "DMI_CPU0_PCH_RX_C_DP<1>")
	)
	(arc
		(start 353.658678 -227.155502)
		(mid 353.50019 -227.204435)
		(end 353.336098 -227.18014)
		(width 0.0889)
		(layer "In6.Cu")
		(net "DMI_CPU0_PCH_RX_C_DP<1>")
	)
	(arc
		(start 359.393236 -216.574878)
		(mid 359.110534 -216.499102)
		(end 358.827832 -216.574878)
		(width 0.0889)
		(layer "In6.Cu")
		(net "DMI_CPU0_PCH_RX_C_DP<1>")
	)
	(arc
		(start 354.78593 -223.584262)
		(mid 354.73366 -223.766627)
		(end 354.598732 -223.899984)
		(width 0.0889)
		(layer "In6.Cu")
		(net "DMI_CPU0_PCH_RX_C_DP<1>")
	)
	(arc
		(start 356.486968 -218.372944)
		(mid 356.665444 -218.692222)
		(end 356.486968 -219.0115)
		(width 0.0889)
		(layer "In6.Cu")
		(net "DMI_CPU0_PCH_RX_C_DP<1>")
	)
	(segment
		(start 352.531934 -228.459284)
		(end 352.53168 -228.45903)
		(width 0.13208)
		(layer "F.Cu")
		(net "DMI_CPU0_PCH_RX_C_DP<0>")
	)
	(segment
		(start 352.531934 -228.99497)
		(end 352.531934 -228.459284)
		(width 0.13208)
		(layer "F.Cu")
		(net "DMI_CPU0_PCH_RX_C_DP<0>")
	)
	(segment
		(start 332.711298 -79.325724)
		(end 335.377028 -72.892412)
		(width 0.13208)
		(layer "B.Cu")
		(net "DMI_CPU0_PCH_RX_C_DP<0>")
	)
	(segment
		(start 335.377028 -72.892412)
		(end 336.05724 -72.2122)
		(width 0.13208)
		(layer "B.Cu")
		(net "DMI_CPU0_PCH_RX_C_DP<0>")
	)
	(segment
		(start 337.823302 -64.922908)
		(end 337.823302 -64.892428)
		(width 0.13208)
		(layer "B.Cu")
		(net "DMI_CPU0_PCH_RX_C_DP<0>")
	)
	(segment
		(start 337.820762 -65.427098)
		(end 337.820762 -64.925448)
		(width 0.13208)
		(layer "B.Cu")
		(net "DMI_CPU0_PCH_RX_C_DP<0>")
	)
	(segment
		(start 333.013558 -82.040984)
		(end 332.711298 -81.738724)
		(width 0.13208)
		(layer "B.Cu")
		(net "DMI_CPU0_PCH_RX_C_DP<0>")
	)
	(segment
		(start 336.05724 -72.2122)
		(end 337.508596 -71.610982)
		(width 0.13208)
		(layer "B.Cu")
		(net "DMI_CPU0_PCH_RX_C_DP<0>")
	)
	(segment
		(start 332.711298 -81.738724)
		(end 332.711298 -79.325724)
		(width 0.13208)
		(layer "B.Cu")
		(net "DMI_CPU0_PCH_RX_C_DP<0>")
	)
	(segment
		(start 337.823302 -64.892428)
		(end 338.133182 -64.582548)
		(width 0.13208)
		(layer "B.Cu")
		(net "DMI_CPU0_PCH_RX_C_DP<0>")
	)
	(segment
		(start 337.508596 -71.610982)
		(end 337.867244 -71.252334)
		(width 0.13208)
		(layer "B.Cu")
		(net "DMI_CPU0_PCH_RX_C_DP<0>")
	)
	(segment
		(start 338.22386 -66.400172)
		(end 337.820762 -65.427098)
		(width 0.13208)
		(layer "B.Cu")
		(net "DMI_CPU0_PCH_RX_C_DP<0>")
	)
	(segment
		(start 338.22386 -70.391274)
		(end 338.22386 -66.400172)
		(width 0.13208)
		(layer "B.Cu")
		(net "DMI_CPU0_PCH_RX_C_DP<0>")
	)
	(segment
		(start 337.820762 -64.925448)
		(end 337.823302 -64.922908)
		(width 0.13208)
		(layer "B.Cu")
		(net "DMI_CPU0_PCH_RX_C_DP<0>")
	)
	(segment
		(start 337.867244 -71.252334)
		(end 338.22386 -70.391274)
		(width 0.13208)
		(layer "B.Cu")
		(net "DMI_CPU0_PCH_RX_C_DP<0>")
	)
	(segment
		(start 355.625146 -217.559128)
		(end 355.634036 -217.554048)
		(width 0.0889)
		(layer "In6.Cu")
		(net "DMI_CPU0_PCH_RX_C_DP<0>")
	)
	(segment
		(start 356.103174 -216.740486)
		(end 356.103936 -216.739978)
		(width 0.0889)
		(layer "In6.Cu")
		(net "DMI_CPU0_PCH_RX_C_DP<0>")
	)
	(segment
		(start 353.284282 -226.506786)
		(end 353.285044 -226.506278)
		(width 0.0889)
		(layer "In6.Cu")
		(net "DMI_CPU0_PCH_RX_C_DP<0>")
	)
	(segment
		(start 356.100634 -216.74201)
		(end 356.101396 -216.741502)
		(width 0.0889)
		(layer "In6.Cu")
		(net "DMI_CPU0_PCH_RX_C_DP<0>")
	)
	(segment
		(start 374.62206 -157.547818)
		(end 334.829912 -91.560142)
		(width 0.14732)
		(layer "In6.Cu")
		(net "DMI_CPU0_PCH_RX_C_DP<0>")
	)
	(segment
		(start 356.564946 -215.931242)
		(end 356.573836 -215.926162)
		(width 0.0889)
		(layer "In6.Cu")
		(net "DMI_CPU0_PCH_RX_C_DP<0>")
	)
	(segment
		(start 355.162358 -221.624144)
		(end 355.163882 -221.623382)
		(width 0.0889)
		(layer "In6.Cu")
		(net "DMI_CPU0_PCH_RX_C_DP<0>")
	)
	(segment
		(start 354.506784 -222.780098)
		(end 354.506784 -222.761556)
		(width 0.0889)
		(layer "In6.Cu")
		(net "DMI_CPU0_PCH_RX_C_DP<0>")
	)
	(segment
		(start 367.13033 -195.411598)
		(end 367.130076 -195.41109)
		(width 0.14732)
		(layer "In6.Cu")
		(net "DMI_CPU0_PCH_RX_C_DP<0>")
	)
	(segment
		(start 360.332274 -213.082886)
		(end 360.332274 -212.674962)
		(width 0.0889)
		(layer "In6.Cu")
		(net "DMI_CPU0_PCH_RX_C_DP<0>")
	)
	(segment
		(start 359.67543 -215.452198)
		(end 359.67543 -215.436704)
		(width 0.0889)
		(layer "In6.Cu")
		(net "DMI_CPU0_PCH_RX_C_DP<0>")
	)
	(segment
		(start 354.976684 -220.32849)
		(end 354.976684 -220.311218)
		(width 0.0889)
		(layer "In6.Cu")
		(net "DMI_CPU0_PCH_RX_C_DP<0>")
	)
	(segment
		(start 360.332274 -214.670386)
		(end 360.332274 -213.083394)
		(width 0.0889)
		(layer "In6.Cu")
		(net "DMI_CPU0_PCH_RX_C_DP<0>")
	)
	(segment
		(start 355.164644 -221.622874)
		(end 355.169978 -221.619826)
		(width 0.0889)
		(layer "In6.Cu")
		(net "DMI_CPU0_PCH_RX_C_DP<0>")
	)
	(segment
		(start 356.101396 -216.741502)
		(end 356.103174 -216.740486)
		(width 0.0889)
		(layer "In6.Cu")
		(net "DMI_CPU0_PCH_RX_C_DP<0>")
	)
	(segment
		(start 352.53168 -228.45903)
		(end 352.375216 -228.188012)
		(width 0.0889)
		(layer "In6.Cu")
		(net "DMI_CPU0_PCH_RX_C_DP<0>")
	)
	(segment
		(start 355.163882 -221.623382)
		(end 355.164644 -221.622874)
		(width 0.0889)
		(layer "In6.Cu")
		(net "DMI_CPU0_PCH_RX_C_DP<0>")
	)
	(segment
		(start 354.97643 -221.963234)
		(end 354.97643 -221.94774)
		(width 0.0889)
		(layer "In6.Cu")
		(net "DMI_CPU0_PCH_RX_C_DP<0>")
	)
	(segment
		(start 355.634036 -218.202764)
		(end 355.625146 -218.197684)
		(width 0.0889)
		(layer "In6.Cu")
		(net "DMI_CPU0_PCH_RX_C_DP<0>")
	)
	(segment
		(start 360.374184 -209.263996)
		(end 361.361228 -203.650088)
		(width 0.14732)
		(layer "In6.Cu")
		(net "DMI_CPU0_PCH_RX_C_DP<0>")
	)
	(segment
		(start 353.754436 -224.7138)
		(end 353.75342 -224.713292)
		(width 0.0889)
		(layer "In6.Cu")
		(net "DMI_CPU0_PCH_RX_C_DP<0>")
	)
	(segment
		(start 353.75342 -225.693478)
		(end 353.754436 -225.69297)
		(width 0.0889)
		(layer "In6.Cu")
		(net "DMI_CPU0_PCH_RX_C_DP<0>")
	)
	(segment
		(start 355.916484 -217.07856)
		(end 355.916484 -217.064336)
		(width 0.0889)
		(layer "In6.Cu")
		(net "DMI_CPU0_PCH_RX_C_DP<0>")
	)
	(segment
		(start 352.627184 -227.659184)
		(end 352.627184 -227.64496)
		(width 0.0889)
		(layer "In6.Cu")
		(net "DMI_CPU0_PCH_RX_C_DP<0>")
	)
	(segment
		(start 354.215446 -223.256348)
		(end 354.224336 -223.251268)
		(width 0.0889)
		(layer "In6.Cu")
		(net "DMI_CPU0_PCH_RX_C_DP<0>")
	)
	(segment
		(start 353.097084 -226.84105)
		(end 353.097084 -226.822508)
		(width 0.0889)
		(layer "In6.Cu")
		(net "DMI_CPU0_PCH_RX_C_DP<0>")
	)
	(segment
		(start 355.164644 -219.994988)
		(end 355.169978 -219.99194)
		(width 0.0889)
		(layer "In6.Cu")
		(net "DMI_CPU0_PCH_RX_C_DP<0>")
	)
	(segment
		(start 355.625146 -219.18676)
		(end 355.634036 -219.18168)
		(width 0.0889)
		(layer "In6.Cu")
		(net "DMI_CPU0_PCH_RX_C_DP<0>")
	)
	(segment
		(start 353.285044 -226.506278)
		(end 353.290378 -226.50323)
		(width 0.0889)
		(layer "In6.Cu")
		(net "DMI_CPU0_PCH_RX_C_DP<0>")
	)
	(segment
		(start 356.095046 -216.745058)
		(end 356.100634 -216.74201)
		(width 0.0889)
		(layer "In6.Cu")
		(net "DMI_CPU0_PCH_RX_C_DP<0>")
	)
	(segment
		(start 334.829912 -91.560142)
		(end 332.718918 -83.9724)
		(width 0.14732)
		(layer "In6.Cu")
		(net "DMI_CPU0_PCH_RX_C_DP<0>")
	)
	(segment
		(start 353.75342 -224.713292)
		(end 353.745546 -224.70872)
		(width 0.0889)
		(layer "In6.Cu")
		(net "DMI_CPU0_PCH_RX_C_DP<0>")
	)
	(segment
		(start 353.745546 -224.070164)
		(end 353.754436 -224.065084)
		(width 0.0889)
		(layer "In6.Cu")
		(net "DMI_CPU0_PCH_RX_C_DP<0>")
	)
	(segment
		(start 355.163882 -219.995496)
		(end 355.164644 -219.994988)
		(width 0.0889)
		(layer "In6.Cu")
		(net "DMI_CPU0_PCH_RX_C_DP<0>")
	)
	(segment
		(start 352.375216 -228.188012)
		(end 352.399346 -228.098858)
		(width 0.0889)
		(layer "In6.Cu")
		(net "DMI_CPU0_PCH_RX_C_DP<0>")
	)
	(segment
		(start 359.853992 -215.117426)
		(end 359.862882 -215.112346)
		(width 0.0889)
		(layer "In6.Cu")
		(net "DMI_CPU0_PCH_RX_C_DP<0>")
	)
	(segment
		(start 355.446584 -221.133924)
		(end 355.446584 -221.1197)
		(width 0.0889)
		(layer "In6.Cu")
		(net "DMI_CPU0_PCH_RX_C_DP<0>")
	)
	(segment
		(start 354.03663 -225.225356)
		(end 354.03663 -225.187764)
		(width 0.0889)
		(layer "In6.Cu")
		(net "DMI_CPU0_PCH_RX_C_DP<0>")
	)
	(segment
		(start 356.386384 -216.260426)
		(end 356.386384 -216.25052)
		(width 0.0889)
		(layer "In6.Cu")
		(net "DMI_CPU0_PCH_RX_C_DP<0>")
	)
	(segment
		(start 376.056652 -186.394852)
		(end 377.885198 -176.035716)
		(width 0.14732)
		(layer "In6.Cu")
		(net "DMI_CPU0_PCH_RX_C_DP<0>")
	)
	(segment
		(start 357.888032 -215.926162)
		(end 357.902764 -215.934798)
		(width 0.0889)
		(layer "In6.Cu")
		(net "DMI_CPU0_PCH_RX_C_DP<0>")
	)
	(segment
		(start 360.332528 -213.08314)
		(end 360.332274 -213.082886)
		(width 0.0889)
		(layer "In6.Cu")
		(net "DMI_CPU0_PCH_RX_C_DP<0>")
	)
	(segment
		(start 332.718918 -83.9724)
		(end 332.718918 -82.335624)
		(width 0.14732)
		(layer "In6.Cu")
		(net "DMI_CPU0_PCH_RX_C_DP<0>")
	)
	(segment
		(start 360.374184 -212.610954)
		(end 360.374184 -209.263996)
		(width 0.14732)
		(layer "In6.Cu")
		(net "DMI_CPU0_PCH_RX_C_DP<0>")
	)
	(segment
		(start 356.948232 -215.926162)
		(end 356.962964 -215.934798)
		(width 0.0889)
		(layer "In6.Cu")
		(net "DMI_CPU0_PCH_RX_C_DP<0>")
	)
	(segment
		(start 377.885198 -176.035716)
		(end 374.62206 -157.547818)
		(width 0.14732)
		(layer "In6.Cu")
		(net "DMI_CPU0_PCH_RX_C_DP<0>")
	)
	(segment
		(start 360.374184 -212.633052)
		(end 360.374184 -212.610954)
		(width 0.0889)
		(layer "In6.Cu")
		(net "DMI_CPU0_PCH_RX_C_DP<0>")
	)
	(segment
		(start 353.754436 -224.065084)
		(end 353.760532 -224.061528)
		(width 0.0889)
		(layer "In6.Cu")
		(net "DMI_CPU0_PCH_RX_C_DP<0>")
	)
	(segment
		(start 358.827832 -215.926162)
		(end 358.842564 -215.934798)
		(width 0.0889)
		(layer "In6.Cu")
		(net "DMI_CPU0_PCH_RX_C_DP<0>")
	)
	(segment
		(start 354.685346 -222.442278)
		(end 354.694236 -222.437198)
		(width 0.0889)
		(layer "In6.Cu")
		(net "DMI_CPU0_PCH_RX_C_DP<0>")
	)
	(segment
		(start 355.154992 -221.628462)
		(end 355.162358 -221.624144)
		(width 0.0889)
		(layer "In6.Cu")
		(net "DMI_CPU0_PCH_RX_C_DP<0>")
	)
	(segment
		(start 361.361228 -203.650088)
		(end 367.13033 -195.411598)
		(width 0.14732)
		(layer "In6.Cu")
		(net "DMI_CPU0_PCH_RX_C_DP<0>")
	)
	(segment
		(start 360.332274 -212.674962)
		(end 360.374184 -212.633052)
		(width 0.0889)
		(layer "In6.Cu")
		(net "DMI_CPU0_PCH_RX_C_DP<0>")
	)
	(segment
		(start 353.745546 -225.69805)
		(end 353.75342 -225.693478)
		(width 0.0889)
		(layer "In6.Cu")
		(net "DMI_CPU0_PCH_RX_C_DP<0>")
	)
	(segment
		(start 332.718918 -82.335624)
		(end 333.013558 -82.040984)
		(width 0.14732)
		(layer "In6.Cu")
		(net "DMI_CPU0_PCH_RX_C_DP<0>")
	)
	(segment
		(start 367.130076 -195.41109)
		(end 372.256304 -191.822832)
		(width 0.14732)
		(layer "In6.Cu")
		(net "DMI_CPU0_PCH_RX_C_DP<0>")
	)
	(segment
		(start 352.805746 -227.325682)
		(end 352.814636 -227.320602)
		(width 0.0889)
		(layer "In6.Cu")
		(net "DMI_CPU0_PCH_RX_C_DP<0>")
	)
	(segment
		(start 355.91623 -218.707716)
		(end 355.91623 -218.676728)
		(width 0.0889)
		(layer "In6.Cu")
		(net "DMI_CPU0_PCH_RX_C_DP<0>")
	)
	(segment
		(start 372.256304 -191.822832)
		(end 376.056652 -186.394852)
		(width 0.14732)
		(layer "In6.Cu")
		(net "DMI_CPU0_PCH_RX_C_DP<0>")
	)
	(segment
		(start 359.98023 -215.02243)
		(end 360.332274 -214.670386)
		(width 0.0889)
		(layer "In6.Cu")
		(net "DMI_CPU0_PCH_RX_C_DP<0>")
	)
	(segment
		(start 360.332274 -213.083394)
		(end 360.332528 -213.08314)
		(width 0.0889)
		(layer "In6.Cu")
		(net "DMI_CPU0_PCH_RX_C_DP<0>")
	)
	(arc
		(start 354.03663 -225.187764)
		(mid 353.95726 -224.91403)
		(end 353.754436 -224.7138)
		(width 0.0889)
		(layer "In6.Cu")
		(net "DMI_CPU0_PCH_RX_C_DP<0>")
	)
	(arc
		(start 355.446584 -217.878406)
		(mid 355.446636 -217.871039)
		(end 355.446838 -217.863674)
		(width 0.0889)
		(layer "In6.Cu")
		(net "DMI_CPU0_PCH_RX_C_DP<0>")
	)
	(arc
		(start 352.814636 -227.320602)
		(mid 353.018971 -227.117997)
		(end 353.097084 -226.84105)
		(width 0.0889)
		(layer "In6.Cu")
		(net "DMI_CPU0_PCH_RX_C_DP<0>")
	)
	(arc
		(start 355.634036 -219.18168)
		(mid 355.836859 -218.981449)
		(end 355.91623 -218.707716)
		(width 0.0889)
		(layer "In6.Cu")
		(net "DMI_CPU0_PCH_RX_C_DP<0>")
	)
	(arc
		(start 357.513636 -215.926162)
		(mid 357.700834 -215.876019)
		(end 357.888032 -215.926162)
		(width 0.0889)
		(layer "In6.Cu")
		(net "DMI_CPU0_PCH_RX_C_DP<0>")
	)
	(arc
		(start 358.453436 -215.926162)
		(mid 358.640634 -215.876019)
		(end 358.827832 -215.926162)
		(width 0.0889)
		(layer "In6.Cu")
		(net "DMI_CPU0_PCH_RX_C_DP<0>")
	)
	(arc
		(start 354.976684 -220.311218)
		(mid 355.028954 -220.128853)
		(end 355.163882 -219.995496)
		(width 0.0889)
		(layer "In6.Cu")
		(net "DMI_CPU0_PCH_RX_C_DP<0>")
	)
	(arc
		(start 358.842564 -215.934798)
		(mid 359.393757 -215.926)
		(end 359.67543 -215.452198)
		(width 0.0889)
		(layer "In6.Cu")
		(net "DMI_CPU0_PCH_RX_C_DP<0>")
	)
	(arc
		(start 354.506784 -222.761556)
		(mid 354.554463 -222.578656)
		(end 354.685346 -222.442278)
		(width 0.0889)
		(layer "In6.Cu")
		(net "DMI_CPU0_PCH_RX_C_DP<0>")
	)
	(arc
		(start 359.67543 -215.436704)
		(mid 359.723109 -215.253804)
		(end 359.853992 -215.117426)
		(width 0.0889)
		(layer "In6.Cu")
		(net "DMI_CPU0_PCH_RX_C_DP<0>")
	)
	(arc
		(start 355.446584 -221.1197)
		(mid 355.367365 -220.845015)
		(end 355.163882 -220.644212)
		(width 0.0889)
		(layer "In6.Cu")
		(net "DMI_CPU0_PCH_RX_C_DP<0>")
	)
	(arc
		(start 352.627184 -227.64496)
		(mid 352.674863 -227.46206)
		(end 352.805746 -227.325682)
		(width 0.0889)
		(layer "In6.Cu")
		(net "DMI_CPU0_PCH_RX_C_DP<0>")
	)
	(arc
		(start 353.754436 -225.69297)
		(mid 353.955718 -225.495483)
		(end 354.03663 -225.225356)
		(width 0.0889)
		(layer "In6.Cu")
		(net "DMI_CPU0_PCH_RX_C_DP<0>")
	)
	(arc
		(start 355.916484 -217.064336)
		(mid 355.964163 -216.881436)
		(end 356.095046 -216.745058)
		(width 0.0889)
		(layer "In6.Cu")
		(net "DMI_CPU0_PCH_RX_C_DP<0>")
	)
	(arc
		(start 355.446838 -217.863674)
		(mid 355.497892 -217.689094)
		(end 355.625146 -217.559128)
		(width 0.0889)
		(layer "In6.Cu")
		(net "DMI_CPU0_PCH_RX_C_DP<0>")
	)
	(arc
		(start 354.224336 -223.251268)
		(mid 354.426622 -223.052287)
		(end 354.506784 -222.780098)
		(width 0.0889)
		(layer "In6.Cu")
		(net "DMI_CPU0_PCH_RX_C_DP<0>")
	)
	(arc
		(start 356.103936 -216.739978)
		(mid 356.308271 -216.537373)
		(end 356.386384 -216.260426)
		(width 0.0889)
		(layer "In6.Cu")
		(net "DMI_CPU0_PCH_RX_C_DP<0>")
	)
	(arc
		(start 355.163882 -220.644212)
		(mid 355.028949 -220.510858)
		(end 354.976684 -220.32849)
		(width 0.0889)
		(layer "In6.Cu")
		(net "DMI_CPU0_PCH_RX_C_DP<0>")
	)
	(arc
		(start 354.97643 -221.94774)
		(mid 355.024109 -221.76484)
		(end 355.154992 -221.628462)
		(width 0.0889)
		(layer "In6.Cu")
		(net "DMI_CPU0_PCH_RX_C_DP<0>")
	)
	(arc
		(start 359.862882 -215.112346)
		(mid 359.924515 -215.071249)
		(end 359.98023 -215.02243)
		(width 0.0889)
		(layer "In6.Cu")
		(net "DMI_CPU0_PCH_RX_C_DP<0>")
	)
	(arc
		(start 355.169978 -219.99194)
		(mid 355.372565 -219.785589)
		(end 355.446584 -219.506038)
		(width 0.0889)
		(layer "In6.Cu")
		(net "DMI_CPU0_PCH_RX_C_DP<0>")
	)
	(arc
		(start 355.634036 -217.554048)
		(mid 355.837341 -217.353182)
		(end 355.916484 -217.07856)
		(width 0.0889)
		(layer "In6.Cu")
		(net "DMI_CPU0_PCH_RX_C_DP<0>")
	)
	(arc
		(start 356.386384 -216.25052)
		(mid 356.434063 -216.06762)
		(end 356.564946 -215.931242)
		(width 0.0889)
		(layer "In6.Cu")
		(net "DMI_CPU0_PCH_RX_C_DP<0>")
	)
	(arc
		(start 355.169978 -221.619826)
		(mid 355.372565 -221.413475)
		(end 355.446584 -221.133924)
		(width 0.0889)
		(layer "In6.Cu")
		(net "DMI_CPU0_PCH_RX_C_DP<0>")
	)
	(arc
		(start 356.573836 -215.926162)
		(mid 356.761034 -215.876019)
		(end 356.948232 -215.926162)
		(width 0.0889)
		(layer "In6.Cu")
		(net "DMI_CPU0_PCH_RX_C_DP<0>")
	)
	(arc
		(start 355.91623 -218.676728)
		(mid 355.83686 -218.402994)
		(end 355.634036 -218.202764)
		(width 0.0889)
		(layer "In6.Cu")
		(net "DMI_CPU0_PCH_RX_C_DP<0>")
	)
	(arc
		(start 355.446584 -219.506038)
		(mid 355.494263 -219.323138)
		(end 355.625146 -219.18676)
		(width 0.0889)
		(layer "In6.Cu")
		(net "DMI_CPU0_PCH_RX_C_DP<0>")
	)
	(arc
		(start 352.399346 -228.098858)
		(mid 352.407918 -228.092335)
		(end 352.416364 -228.08565)
		(width 0.0889)
		(layer "In6.Cu")
		(net "DMI_CPU0_PCH_RX_C_DP<0>")
	)
	(arc
		(start 353.566984 -226.017328)
		(mid 353.567036 -226.009961)
		(end 353.567238 -226.002596)
		(width 0.0889)
		(layer "In6.Cu")
		(net "DMI_CPU0_PCH_RX_C_DP<0>")
	)
	(arc
		(start 357.902764 -215.934798)
		(mid 358.179239 -216.002118)
		(end 358.453436 -215.926162)
		(width 0.0889)
		(layer "In6.Cu")
		(net "DMI_CPU0_PCH_RX_C_DP<0>")
	)
	(arc
		(start 354.036884 -223.575626)
		(mid 354.084563 -223.392726)
		(end 354.215446 -223.256348)
		(width 0.0889)
		(layer "In6.Cu")
		(net "DMI_CPU0_PCH_RX_C_DP<0>")
	)
	(arc
		(start 353.760532 -224.061528)
		(mid 353.962945 -223.855115)
		(end 354.036884 -223.575626)
		(width 0.0889)
		(layer "In6.Cu")
		(net "DMI_CPU0_PCH_RX_C_DP<0>")
	)
	(arc
		(start 353.290378 -226.50323)
		(mid 353.492965 -226.296879)
		(end 353.566984 -226.017328)
		(width 0.0889)
		(layer "In6.Cu")
		(net "DMI_CPU0_PCH_RX_C_DP<0>")
	)
	(arc
		(start 355.625146 -218.197684)
		(mid 355.494232 -218.061324)
		(end 355.446584 -217.878406)
		(width 0.0889)
		(layer "In6.Cu")
		(net "DMI_CPU0_PCH_RX_C_DP<0>")
	)
	(arc
		(start 354.694236 -222.437198)
		(mid 354.897059 -222.236967)
		(end 354.97643 -221.963234)
		(width 0.0889)
		(layer "In6.Cu")
		(net "DMI_CPU0_PCH_RX_C_DP<0>")
	)
	(arc
		(start 353.745546 -224.70872)
		(mid 353.56707 -224.389442)
		(end 353.745546 -224.070164)
		(width 0.0889)
		(layer "In6.Cu")
		(net "DMI_CPU0_PCH_RX_C_DP<0>")
	)
	(arc
		(start 352.416364 -228.08565)
		(mid 352.568795 -227.895668)
		(end 352.627184 -227.659184)
		(width 0.0889)
		(layer "In6.Cu")
		(net "DMI_CPU0_PCH_RX_C_DP<0>")
	)
	(arc
		(start 353.567238 -226.002596)
		(mid 353.618292 -225.828016)
		(end 353.745546 -225.69805)
		(width 0.0889)
		(layer "In6.Cu")
		(net "DMI_CPU0_PCH_RX_C_DP<0>")
	)
	(arc
		(start 353.097084 -226.822508)
		(mid 353.149354 -226.640143)
		(end 353.284282 -226.506786)
		(width 0.0889)
		(layer "In6.Cu")
		(net "DMI_CPU0_PCH_RX_C_DP<0>")
	)
	(arc
		(start 356.962964 -215.934798)
		(mid 357.239439 -216.002118)
		(end 357.513636 -215.926162)
		(width 0.0889)
		(layer "In6.Cu")
		(net "DMI_CPU0_PCH_RX_C_DP<0>")
	)
	(segment
		(start 359.110534 -227.367084)
		(end 359.110534 -226.831398)
		(width 0.13208)
		(layer "F.Cu")
		(net "DMI_CPU0_PCH_RX_C_DN<7>")
	)
	(segment
		(start 359.110534 -226.831398)
		(end 359.11028 -226.831144)
		(width 0.13208)
		(layer "F.Cu")
		(net "DMI_CPU0_PCH_RX_C_DN<7>")
	)
	(segment
		(start 352.125788 -73.298304)
		(end 352.288602 -73.23074)
		(width 0.13208)
		(layer "B.Cu")
		(net "DMI_CPU0_PCH_RX_C_DN<7>")
	)
	(segment
		(start 351.536 -66.208148)
		(end 351.035874 -65.000886)
		(width 0.13208)
		(layer "B.Cu")
		(net "DMI_CPU0_PCH_RX_C_DN<7>")
	)
	(segment
		(start 352.675698 -72.296528)
		(end 352.82124 -71.944738)
		(width 0.13208)
		(layer "B.Cu")
		(net "DMI_CPU0_PCH_RX_C_DN<7>")
	)
	(segment
		(start 352.51263 -72.364092)
		(end 352.675698 -72.296528)
		(width 0.13208)
		(layer "B.Cu")
		(net "DMI_CPU0_PCH_RX_C_DN<7>")
	)
	(segment
		(start 353.2378 -67.909948)
		(end 351.536 -66.208148)
		(width 0.13208)
		(layer "B.Cu")
		(net "DMI_CPU0_PCH_RX_C_DN<7>")
	)
	(segment
		(start 352.047302 -73.813162)
		(end 351.979992 -73.650348)
		(width 0.13208)
		(layer "B.Cu")
		(net "DMI_CPU0_PCH_RX_C_DN<7>")
	)
	(segment
		(start 351.66046 -74.747374)
		(end 351.592896 -74.58456)
		(width 0.13208)
		(layer "B.Cu")
		(net "DMI_CPU0_PCH_RX_C_DN<7>")
	)
	(segment
		(start 351.592896 -74.58456)
		(end 351.738692 -74.232516)
		(width 0.13208)
		(layer "B.Cu")
		(net "DMI_CPU0_PCH_RX_C_DN<7>")
	)
	(segment
		(start 351.979992 -73.650348)
		(end 352.125788 -73.298304)
		(width 0.13208)
		(layer "B.Cu")
		(net "DMI_CPU0_PCH_RX_C_DN<7>")
	)
	(segment
		(start 351.738692 -74.232516)
		(end 351.90176 -74.164952)
		(width 0.13208)
		(layer "B.Cu")
		(net "DMI_CPU0_PCH_RX_C_DN<7>")
	)
	(segment
		(start 353.2378 -70.939152)
		(end 353.2378 -67.909948)
		(width 0.13208)
		(layer "B.Cu")
		(net "DMI_CPU0_PCH_RX_C_DN<7>")
	)
	(segment
		(start 353.06254 -71.36257)
		(end 353.2378 -70.939152)
		(width 0.13208)
		(layer "B.Cu")
		(net "DMI_CPU0_PCH_RX_C_DN<7>")
	)
	(segment
		(start 351.035874 -65.000886)
		(end 350.802448 -64.76746)
		(width 0.13208)
		(layer "B.Cu")
		(net "DMI_CPU0_PCH_RX_C_DN<7>")
	)
	(segment
		(start 345.328494 -84.09559)
		(end 345.328494 -81.645506)
		(width 0.13208)
		(layer "B.Cu")
		(net "DMI_CPU0_PCH_RX_C_DN<7>")
	)
	(segment
		(start 350.802448 -64.76746)
		(end 350.270064 -64.76746)
		(width 0.13208)
		(layer "B.Cu")
		(net "DMI_CPU0_PCH_RX_C_DN<7>")
	)
	(segment
		(start 352.75393 -71.782178)
		(end 352.899726 -71.42988)
		(width 0.13208)
		(layer "B.Cu")
		(net "DMI_CPU0_PCH_RX_C_DN<7>")
	)
	(segment
		(start 345.026234 -84.39785)
		(end 345.328494 -84.09559)
		(width 0.13208)
		(layer "B.Cu")
		(net "DMI_CPU0_PCH_RX_C_DN<7>")
	)
	(segment
		(start 352.366834 -72.716136)
		(end 352.51263 -72.364092)
		(width 0.13208)
		(layer "B.Cu")
		(net "DMI_CPU0_PCH_RX_C_DN<7>")
	)
	(segment
		(start 351.90176 -74.164952)
		(end 352.047302 -73.813162)
		(width 0.13208)
		(layer "B.Cu")
		(net "DMI_CPU0_PCH_RX_C_DN<7>")
	)
	(segment
		(start 352.434398 -72.87895)
		(end 352.366834 -72.716136)
		(width 0.13208)
		(layer "B.Cu")
		(net "DMI_CPU0_PCH_RX_C_DN<7>")
	)
	(segment
		(start 352.899726 -71.42988)
		(end 353.06254 -71.36257)
		(width 0.13208)
		(layer "B.Cu")
		(net "DMI_CPU0_PCH_RX_C_DN<7>")
	)
	(segment
		(start 352.288602 -73.23074)
		(end 352.434398 -72.87895)
		(width 0.13208)
		(layer "B.Cu")
		(net "DMI_CPU0_PCH_RX_C_DN<7>")
	)
	(segment
		(start 352.82124 -71.944738)
		(end 352.75393 -71.782178)
		(width 0.13208)
		(layer "B.Cu")
		(net "DMI_CPU0_PCH_RX_C_DN<7>")
	)
	(segment
		(start 350.270064 -64.76746)
		(end 349.942404 -65.09512)
		(width 0.13208)
		(layer "B.Cu")
		(net "DMI_CPU0_PCH_RX_C_DN<7>")
	)
	(segment
		(start 351.260156 -75.713844)
		(end 351.66046 -74.747374)
		(width 0.13208)
		(layer "B.Cu")
		(net "DMI_CPU0_PCH_RX_C_DN<7>")
	)
	(segment
		(start 345.328494 -81.645506)
		(end 351.260156 -75.713844)
		(width 0.13208)
		(layer "B.Cu")
		(net "DMI_CPU0_PCH_RX_C_DN<7>")
	)
	(segment
		(start 360.42473 -223.584262)
		(end 360.42473 -223.561402)
		(width 0.0889)
		(layer "In6.Cu")
		(net "DMI_CPU0_PCH_RX_C_DN<7>")
	)
	(segment
		(start 364.460536 -219.833952)
		(end 364.475522 -219.825062)
		(width 0.0889)
		(layer "In6.Cu")
		(net "DMI_CPU0_PCH_RX_C_DN<7>")
	)
	(segment
		(start 366.953546 -208.178654)
		(end 367.198402 -206.789274)
		(width 0.14732)
		(layer "In6.Cu")
		(net "DMI_CPU0_PCH_RX_C_DN<7>")
	)
	(segment
		(start 345.320874 -84.69249)
		(end 345.026234 -84.39785)
		(width 0.14732)
		(layer "In6.Cu")
		(net "DMI_CPU0_PCH_RX_C_DN<7>")
	)
	(segment
		(start 365.407194 -217.554556)
		(end 365.406432 -217.554048)
		(width 0.0889)
		(layer "In6.Cu")
		(net "DMI_CPU0_PCH_RX_C_DN<7>")
	)
	(segment
		(start 366.9538 -211.258912)
		(end 366.953546 -211.258658)
		(width 0.14732)
		(layer "In6.Cu")
		(net "DMI_CPU0_PCH_RX_C_DN<7>")
	)
	(segment
		(start 363.611668 -222.266002)
		(end 363.622082 -222.272098)
		(width 0.0889)
		(layer "In6.Cu")
		(net "DMI_CPU0_PCH_RX_C_DN<7>")
	)
	(segment
		(start 382.81864 -186.916314)
		(end 384.651758 -176.520348)
		(width 0.14732)
		(layer "In6.Cu")
		(net "DMI_CPU0_PCH_RX_C_DN<7>")
	)
	(segment
		(start 366.89665 -212.735922)
		(end 366.99571 -212.636862)
		(width 0.0889)
		(layer "In6.Cu")
		(net "DMI_CPU0_PCH_RX_C_DN<7>")
	)
	(segment
		(start 364.460536 -221.461838)
		(end 364.466632 -221.458282)
		(width 0.0889)
		(layer "In6.Cu")
		(net "DMI_CPU0_PCH_RX_C_DN<7>")
	)
	(segment
		(start 379.932438 -152.136602)
		(end 379.75032 -152.080468)
		(width 0.14732)
		(layer "In6.Cu")
		(net "DMI_CPU0_PCH_RX_C_DN<7>")
	)
	(segment
		(start 364.475522 -220.814646)
		(end 364.466632 -220.809566)
		(width 0.0889)
		(layer "In6.Cu")
		(net "DMI_CPU0_PCH_RX_C_DN<7>")
	)
	(segment
		(start 359.767632 -226.341686)
		(end 359.776522 -226.336606)
		(width 0.0889)
		(layer "In6.Cu")
		(net "DMI_CPU0_PCH_RX_C_DN<7>")
	)
	(segment
		(start 366.99571 -211.515198)
		(end 366.9538 -211.473288)
		(width 0.0889)
		(layer "In6.Cu")
		(net "DMI_CPU0_PCH_RX_C_DN<7>")
	)
	(segment
		(start 364.654084 -219.506038)
		(end 364.654084 -219.490544)
		(width 0.0889)
		(layer "In6.Cu")
		(net "DMI_CPU0_PCH_RX_C_DN<7>")
	)
	(segment
		(start 363.996478 -222.272098)
		(end 364.005368 -222.267018)
		(width 0.0889)
		(layer "In6.Cu")
		(net "DMI_CPU0_PCH_RX_C_DN<7>")
	)
	(segment
		(start 366.89665 -212.009482)
		(end 366.99571 -211.910422)
		(width 0.0889)
		(layer "In6.Cu")
		(net "DMI_CPU0_PCH_RX_C_DN<7>")
	)
	(segment
		(start 359.75544 -226.348798)
		(end 359.767632 -226.341686)
		(width 0.0889)
		(layer "In6.Cu")
		(net "DMI_CPU0_PCH_RX_C_DN<7>")
	)
	(segment
		(start 365.12373 -217.071956)
		(end 365.12373 -217.064336)
		(width 0.0889)
		(layer "In6.Cu")
		(net "DMI_CPU0_PCH_RX_C_DN<7>")
	)
	(segment
		(start 365.593884 -216.25052)
		(end 365.593884 -216.240614)
		(width 0.0889)
		(layer "In6.Cu")
		(net "DMI_CPU0_PCH_RX_C_DN<7>")
	)
	(segment
		(start 366.99571 -211.910422)
		(end 366.99571 -211.515198)
		(width 0.0889)
		(layer "In6.Cu")
		(net "DMI_CPU0_PCH_RX_C_DN<7>")
	)
	(segment
		(start 365.406432 -216.574878)
		(end 365.415322 -216.569798)
		(width 0.0889)
		(layer "In6.Cu")
		(net "DMI_CPU0_PCH_RX_C_DN<7>")
	)
	(segment
		(start 364.936278 -219.01658)
		(end 364.945168 -219.0115)
		(width 0.0889)
		(layer "In6.Cu")
		(net "DMI_CPU0_PCH_RX_C_DN<7>")
	)
	(segment
		(start 345.763342 -87.347044)
		(end 345.320874 -85.560154)
		(width 0.14732)
		(layer "In6.Cu")
		(net "DMI_CPU0_PCH_RX_C_DN<7>")
	)
	(segment
		(start 360.237278 -225.527616)
		(end 360.246168 -225.522536)
		(width 0.0889)
		(layer "In6.Cu")
		(net "DMI_CPU0_PCH_RX_C_DN<7>")
	)
	(segment
		(start 366.89665 -213.000082)
		(end 366.89665 -212.735922)
		(width 0.0889)
		(layer "In6.Cu")
		(net "DMI_CPU0_PCH_RX_C_DN<7>")
	)
	(segment
		(start 364.466632 -221.458282)
		(end 364.475522 -221.453202)
		(width 0.0889)
		(layer "In6.Cu")
		(net "DMI_CPU0_PCH_RX_C_DN<7>")
	)
	(segment
		(start 379.582172 -151.76119)
		(end 379.638306 -151.579326)
		(width 0.14732)
		(layer "In6.Cu")
		(net "DMI_CPU0_PCH_RX_C_DN<7>")
	)
	(segment
		(start 345.320874 -85.560154)
		(end 345.320874 -84.69249)
		(width 0.14732)
		(layer "In6.Cu")
		(net "DMI_CPU0_PCH_RX_C_DN<7>")
	)
	(segment
		(start 364.18393 -220.334078)
		(end 364.18393 -220.319854)
		(width 0.0889)
		(layer "In6.Cu")
		(net "DMI_CPU0_PCH_RX_C_DN<7>")
	)
	(segment
		(start 359.955084 -226.017328)
		(end 359.955084 -225.99523)
		(width 0.0889)
		(layer "In6.Cu")
		(net "DMI_CPU0_PCH_RX_C_DN<7>")
	)
	(segment
		(start 380.100586 -152.455626)
		(end 379.932438 -152.136602)
		(width 0.14732)
		(layer "In6.Cu")
		(net "DMI_CPU0_PCH_RX_C_DN<7>")
	)
	(segment
		(start 365.39424 -216.58199)
		(end 365.406432 -216.574878)
		(width 0.0889)
		(layer "In6.Cu")
		(net "DMI_CPU0_PCH_RX_C_DN<7>")
	)
	(segment
		(start 359.955084 -224.404936)
		(end 359.955084 -224.379536)
		(width 0.0889)
		(layer "In6.Cu")
		(net "DMI_CPU0_PCH_RX_C_DN<7>")
	)
	(segment
		(start 366.99571 -213.099142)
		(end 366.89665 -213.000082)
		(width 0.0889)
		(layer "In6.Cu")
		(net "DMI_CPU0_PCH_RX_C_DN<7>")
	)
	(segment
		(start 379.75032 -152.080468)
		(end 379.582172 -151.76119)
		(width 0.14732)
		(layer "In6.Cu")
		(net "DMI_CPU0_PCH_RX_C_DN<7>")
	)
	(segment
		(start 376.164094 -196.419978)
		(end 382.81864 -186.916314)
		(width 0.14732)
		(layer "In6.Cu")
		(net "DMI_CPU0_PCH_RX_C_DN<7>")
	)
	(segment
		(start 365.406432 -218.202764)
		(end 365.415322 -218.197684)
		(width 0.0889)
		(layer "In6.Cu")
		(net "DMI_CPU0_PCH_RX_C_DN<7>")
	)
	(segment
		(start 366.953546 -211.258658)
		(end 366.953546 -208.178654)
		(width 0.14732)
		(layer "In6.Cu")
		(net "DMI_CPU0_PCH_RX_C_DN<7>")
	)
	(segment
		(start 372.819422 -198.761858)
		(end 376.164094 -196.419978)
		(width 0.14732)
		(layer "In6.Cu")
		(net "DMI_CPU0_PCH_RX_C_DN<7>")
	)
	(segment
		(start 379.638306 -151.579326)
		(end 345.763342 -87.347044)
		(width 0.14732)
		(layer "In6.Cu")
		(net "DMI_CPU0_PCH_RX_C_DN<7>")
	)
	(segment
		(start 360.707432 -223.085914)
		(end 360.722164 -223.077278)
		(width 0.0889)
		(layer "In6.Cu")
		(net "DMI_CPU0_PCH_RX_C_DN<7>")
	)
	(segment
		(start 359.11028 -226.831144)
		(end 358.953816 -227.102162)
		(width 0.0889)
		(layer "In6.Cu")
		(net "DMI_CPU0_PCH_RX_C_DN<7>")
	)
	(segment
		(start 380.562866 -153.331926)
		(end 380.394718 -153.012902)
		(width 0.14732)
		(layer "In6.Cu")
		(net "DMI_CPU0_PCH_RX_C_DN<7>")
	)
	(segment
		(start 362.587032 -223.085914)
		(end 362.595922 -223.080834)
		(width 0.0889)
		(layer "In6.Cu")
		(net "DMI_CPU0_PCH_RX_C_DN<7>")
	)
	(segment
		(start 366.9538 -211.45119)
		(end 366.9538 -211.258912)
		(width 0.14732)
		(layer "In6.Cu")
		(net "DMI_CPU0_PCH_RX_C_DN<7>")
	)
	(segment
		(start 360.246168 -224.88398)
		(end 360.237278 -224.8789)
		(width 0.0889)
		(layer "In6.Cu")
		(net "DMI_CPU0_PCH_RX_C_DN<7>")
	)
	(segment
		(start 362.774484 -222.761556)
		(end 362.774484 -222.75165)
		(width 0.0889)
		(layer "In6.Cu")
		(net "DMI_CPU0_PCH_RX_C_DN<7>")
	)
	(segment
		(start 366.9538 -211.473288)
		(end 366.9538 -211.45119)
		(width 0.0889)
		(layer "In6.Cu")
		(net "DMI_CPU0_PCH_RX_C_DN<7>")
	)
	(segment
		(start 384.651758 -176.520348)
		(end 380.562866 -153.331926)
		(width 0.14732)
		(layer "In6.Cu")
		(net "DMI_CPU0_PCH_RX_C_DN<7>")
	)
	(segment
		(start 380.394718 -153.012902)
		(end 380.2126 -152.956768)
		(width 0.14732)
		(layer "In6.Cu")
		(net "DMI_CPU0_PCH_RX_C_DN<7>")
	)
	(segment
		(start 359.298494 -227.154994)
		(end 359.306368 -227.150422)
		(width 0.0889)
		(layer "In6.Cu")
		(net "DMI_CPU0_PCH_RX_C_DN<7>")
	)
	(segment
		(start 366.99571 -212.636862)
		(end 366.99571 -212.372702)
		(width 0.0889)
		(layer "In6.Cu")
		(net "DMI_CPU0_PCH_RX_C_DN<7>")
	)
	(segment
		(start 366.06353 -215.44534)
		(end 366.06353 -215.436704)
		(width 0.0889)
		(layer "In6.Cu")
		(net "DMI_CPU0_PCH_RX_C_DN<7>")
	)
	(segment
		(start 359.297478 -227.155502)
		(end 359.298494 -227.154994)
		(width 0.0889)
		(layer "In6.Cu")
		(net "DMI_CPU0_PCH_RX_C_DN<7>")
	)
	(segment
		(start 366.99571 -214.31631)
		(end 366.99571 -213.099142)
		(width 0.0889)
		(layer "In6.Cu")
		(net "DMI_CPU0_PCH_RX_C_DN<7>")
	)
	(segment
		(start 365.415322 -217.559128)
		(end 365.407194 -217.554556)
		(width 0.0889)
		(layer "In6.Cu")
		(net "DMI_CPU0_PCH_RX_C_DN<7>")
	)
	(segment
		(start 366.99571 -212.372702)
		(end 366.89665 -212.273642)
		(width 0.0889)
		(layer "In6.Cu")
		(net "DMI_CPU0_PCH_RX_C_DN<7>")
	)
	(segment
		(start 366.340136 -214.950802)
		(end 366.346232 -214.947246)
		(width 0.0889)
		(layer "In6.Cu")
		(net "DMI_CPU0_PCH_RX_C_DN<7>")
	)
	(segment
		(start 366.42421 -214.88781)
		(end 366.99571 -214.31631)
		(width 0.0889)
		(layer "In6.Cu")
		(net "DMI_CPU0_PCH_RX_C_DN<7>")
	)
	(segment
		(start 365.400336 -218.20632)
		(end 365.406432 -218.202764)
		(width 0.0889)
		(layer "In6.Cu")
		(net "DMI_CPU0_PCH_RX_C_DN<7>")
	)
	(segment
		(start 380.044452 -152.63749)
		(end 380.100586 -152.455626)
		(width 0.14732)
		(layer "In6.Cu")
		(net "DMI_CPU0_PCH_RX_C_DN<7>")
	)
	(segment
		(start 380.2126 -152.956768)
		(end 380.044452 -152.63749)
		(width 0.14732)
		(layer "In6.Cu")
		(net "DMI_CPU0_PCH_RX_C_DN<7>")
	)
	(segment
		(start 364.475522 -219.825062)
		(end 364.475522 -219.825316)
		(width 0.0889)
		(layer "In6.Cu")
		(net "DMI_CPU0_PCH_RX_C_DN<7>")
	)
	(segment
		(start 358.953816 -227.102162)
		(end 358.974898 -227.18014)
		(width 0.0889)
		(layer "In6.Cu")
		(net "DMI_CPU0_PCH_RX_C_DN<7>")
	)
	(segment
		(start 366.89665 -212.273642)
		(end 366.89665 -212.009482)
		(width 0.0889)
		(layer "In6.Cu")
		(net "DMI_CPU0_PCH_RX_C_DN<7>")
	)
	(segment
		(start 367.198402 -206.789274)
		(end 372.819422 -198.761858)
		(width 0.14732)
		(layer "In6.Cu")
		(net "DMI_CPU0_PCH_RX_C_DN<7>")
	)
	(arc
		(start 360.424476 -225.21799)
		(mid 360.424673 -225.210625)
		(end 360.42473 -225.203258)
		(width 0.0889)
		(layer "In6.Cu")
		(net "DMI_CPU0_PCH_RX_C_DN<7>")
	)
	(arc
		(start 360.42473 -223.561402)
		(mid 360.503949 -223.286717)
		(end 360.707432 -223.085914)
		(width 0.0889)
		(layer "In6.Cu")
		(net "DMI_CPU0_PCH_RX_C_DN<7>")
	)
	(arc
		(start 360.42473 -225.203258)
		(mid 360.377051 -225.020358)
		(end 360.246168 -224.88398)
		(width 0.0889)
		(layer "In6.Cu")
		(net "DMI_CPU0_PCH_RX_C_DN<7>")
	)
	(arc
		(start 364.005368 -222.267018)
		(mid 364.136282 -222.130658)
		(end 364.18393 -221.94774)
		(width 0.0889)
		(layer "In6.Cu")
		(net "DMI_CPU0_PCH_RX_C_DN<7>")
	)
	(arc
		(start 364.475522 -219.825316)
		(mid 364.606436 -219.688956)
		(end 364.654084 -219.506038)
		(width 0.0889)
		(layer "In6.Cu")
		(net "DMI_CPU0_PCH_RX_C_DN<7>")
	)
	(arc
		(start 360.237278 -224.8789)
		(mid 360.034455 -224.678669)
		(end 359.955084 -224.404936)
		(width 0.0889)
		(layer "In6.Cu")
		(net "DMI_CPU0_PCH_RX_C_DN<7>")
	)
	(arc
		(start 362.774484 -222.75165)
		(mid 362.852595 -222.474701)
		(end 363.056932 -222.272098)
		(width 0.0889)
		(layer "In6.Cu")
		(net "DMI_CPU0_PCH_RX_C_DN<7>")
	)
	(arc
		(start 362.212636 -223.085914)
		(mid 362.399834 -223.136057)
		(end 362.587032 -223.085914)
		(width 0.0889)
		(layer "In6.Cu")
		(net "DMI_CPU0_PCH_RX_C_DN<7>")
	)
	(arc
		(start 360.237532 -223.899984)
		(mid 360.372465 -223.76663)
		(end 360.42473 -223.584262)
		(width 0.0889)
		(layer "In6.Cu")
		(net "DMI_CPU0_PCH_RX_C_DN<7>")
	)
	(arc
		(start 365.12373 -217.064336)
		(mid 365.195965 -216.787812)
		(end 365.39424 -216.58199)
		(width 0.0889)
		(layer "In6.Cu")
		(net "DMI_CPU0_PCH_RX_C_DN<7>")
	)
	(arc
		(start 366.369346 -214.933022)
		(mid 366.397846 -214.911712)
		(end 366.42421 -214.88781)
		(width 0.0889)
		(layer "In6.Cu")
		(net "DMI_CPU0_PCH_RX_C_DN<7>")
	)
	(arc
		(start 359.48493 -226.831144)
		(mid 359.557165 -226.55462)
		(end 359.75544 -226.348798)
		(width 0.0889)
		(layer "In6.Cu")
		(net "DMI_CPU0_PCH_RX_C_DN<7>")
	)
	(arc
		(start 364.654084 -219.490544)
		(mid 364.733454 -219.21681)
		(end 364.936278 -219.01658)
		(width 0.0889)
		(layer "In6.Cu")
		(net "DMI_CPU0_PCH_RX_C_DN<7>")
	)
	(arc
		(start 359.776522 -226.336606)
		(mid 359.907436 -226.200246)
		(end 359.955084 -226.017328)
		(width 0.0889)
		(layer "In6.Cu")
		(net "DMI_CPU0_PCH_RX_C_DN<7>")
	)
	(arc
		(start 359.955084 -225.99523)
		(mid 360.035995 -225.725102)
		(end 360.237278 -225.527616)
		(width 0.0889)
		(layer "In6.Cu")
		(net "DMI_CPU0_PCH_RX_C_DN<7>")
	)
	(arc
		(start 364.18393 -220.319854)
		(mid 364.257921 -220.040288)
		(end 364.460536 -219.833952)
		(width 0.0889)
		(layer "In6.Cu")
		(net "DMI_CPU0_PCH_RX_C_DN<7>")
	)
	(arc
		(start 363.622082 -222.272098)
		(mid 363.80928 -222.322241)
		(end 363.996478 -222.272098)
		(width 0.0889)
		(layer "In6.Cu")
		(net "DMI_CPU0_PCH_RX_C_DN<7>")
	)
	(arc
		(start 365.12373 -218.692222)
		(mid 365.197721 -218.412656)
		(end 365.400336 -218.20632)
		(width 0.0889)
		(layer "In6.Cu")
		(net "DMI_CPU0_PCH_RX_C_DN<7>")
	)
	(arc
		(start 361.647232 -223.085914)
		(mid 361.929934 -223.010172)
		(end 362.212636 -223.085914)
		(width 0.0889)
		(layer "In6.Cu")
		(net "DMI_CPU0_PCH_RX_C_DN<7>")
	)
	(arc
		(start 364.475522 -221.453202)
		(mid 364.65424 -221.133924)
		(end 364.475522 -220.814646)
		(width 0.0889)
		(layer "In6.Cu")
		(net "DMI_CPU0_PCH_RX_C_DN<7>")
	)
	(arc
		(start 364.18393 -221.94774)
		(mid 364.257921 -221.668174)
		(end 364.460536 -221.461838)
		(width 0.0889)
		(layer "In6.Cu")
		(net "DMI_CPU0_PCH_RX_C_DN<7>")
	)
	(arc
		(start 365.415322 -216.569798)
		(mid 365.546236 -216.433438)
		(end 365.593884 -216.25052)
		(width 0.0889)
		(layer "In6.Cu")
		(net "DMI_CPU0_PCH_RX_C_DN<7>")
	)
	(arc
		(start 360.246168 -225.522536)
		(mid 360.373422 -225.39257)
		(end 360.424476 -225.21799)
		(width 0.0889)
		(layer "In6.Cu")
		(net "DMI_CPU0_PCH_RX_C_DN<7>")
	)
	(arc
		(start 361.272836 -223.085914)
		(mid 361.460034 -223.136057)
		(end 361.647232 -223.085914)
		(width 0.0889)
		(layer "In6.Cu")
		(net "DMI_CPU0_PCH_RX_C_DN<7>")
	)
	(arc
		(start 359.955084 -224.379536)
		(mid 360.033195 -224.102587)
		(end 360.237532 -223.899984)
		(width 0.0889)
		(layer "In6.Cu")
		(net "DMI_CPU0_PCH_RX_C_DN<7>")
	)
	(arc
		(start 365.415322 -218.197684)
		(mid 365.593798 -217.878406)
		(end 365.415322 -217.559128)
		(width 0.0889)
		(layer "In6.Cu")
		(net "DMI_CPU0_PCH_RX_C_DN<7>")
	)
	(arc
		(start 364.466632 -220.809566)
		(mid 364.263151 -220.608762)
		(end 364.18393 -220.334078)
		(width 0.0889)
		(layer "In6.Cu")
		(net "DMI_CPU0_PCH_RX_C_DN<7>")
	)
	(arc
		(start 359.306368 -227.150422)
		(mid 359.437282 -227.014062)
		(end 359.48493 -226.831144)
		(width 0.0889)
		(layer "In6.Cu")
		(net "DMI_CPU0_PCH_RX_C_DN<7>")
	)
	(arc
		(start 364.945168 -219.0115)
		(mid 365.076082 -218.87514)
		(end 365.12373 -218.692222)
		(width 0.0889)
		(layer "In6.Cu")
		(net "DMI_CPU0_PCH_RX_C_DN<7>")
	)
	(arc
		(start 362.595922 -223.080834)
		(mid 362.726836 -222.944474)
		(end 362.774484 -222.761556)
		(width 0.0889)
		(layer "In6.Cu")
		(net "DMI_CPU0_PCH_RX_C_DN<7>")
	)
	(arc
		(start 365.593884 -216.240614)
		(mid 365.671995 -215.963665)
		(end 365.876332 -215.761062)
		(width 0.0889)
		(layer "In6.Cu")
		(net "DMI_CPU0_PCH_RX_C_DN<7>")
	)
	(arc
		(start 358.974898 -227.18014)
		(mid 359.138994 -227.204487)
		(end 359.297478 -227.155502)
		(width 0.0889)
		(layer "In6.Cu")
		(net "DMI_CPU0_PCH_RX_C_DN<7>")
	)
	(arc
		(start 363.056932 -222.272098)
		(mid 363.333491 -222.196355)
		(end 363.611668 -222.266002)
		(width 0.0889)
		(layer "In6.Cu")
		(net "DMI_CPU0_PCH_RX_C_DN<7>")
	)
	(arc
		(start 366.06353 -215.436704)
		(mid 366.137521 -215.157138)
		(end 366.340136 -214.950802)
		(width 0.0889)
		(layer "In6.Cu")
		(net "DMI_CPU0_PCH_RX_C_DN<7>")
	)
	(arc
		(start 360.722164 -223.077278)
		(mid 360.998605 -223.010112)
		(end 361.272836 -223.085914)
		(width 0.0889)
		(layer "In6.Cu")
		(net "DMI_CPU0_PCH_RX_C_DN<7>")
	)
	(arc
		(start 365.876332 -215.761062)
		(mid 366.011265 -215.627708)
		(end 366.06353 -215.44534)
		(width 0.0889)
		(layer "In6.Cu")
		(net "DMI_CPU0_PCH_RX_C_DN<7>")
	)
	(arc
		(start 365.406432 -217.554048)
		(mid 365.20136 -217.350369)
		(end 365.12373 -217.071956)
		(width 0.0889)
		(layer "In6.Cu")
		(net "DMI_CPU0_PCH_RX_C_DN<7>")
	)
	(arc
		(start 366.346232 -214.947246)
		(mid 366.357915 -214.940339)
		(end 366.369346 -214.933022)
		(width 0.0889)
		(layer "In6.Cu")
		(net "DMI_CPU0_PCH_RX_C_DN<7>")
	)
	(segment
		(start 358.17048 -228.994716)
		(end 358.17048 -228.45903)
		(width 0.13208)
		(layer "F.Cu")
		(net "DMI_CPU0_PCH_RX_C_DN<6>")
	)
	(segment
		(start 358.170734 -228.99497)
		(end 358.17048 -228.994716)
		(width 0.13208)
		(layer "F.Cu")
		(net "DMI_CPU0_PCH_RX_C_DN<6>")
	)
	(segment
		(start 344.2208 -85.812122)
		(end 343.91854 -85.509862)
		(width 0.13208)
		(layer "B.Cu")
		(net "DMI_CPU0_PCH_RX_C_DN<6>")
	)
	(segment
		(start 349.589852 -69.428106)
		(end 349.0976 -68.240402)
		(width 0.13208)
		(layer "B.Cu")
		(net "DMI_CPU0_PCH_RX_C_DN<6>")
	)
	(segment
		(start 347.74632 -62.883034)
		(end 347.80728 -62.735968)
		(width 0.13208)
		(layer "B.Cu")
		(net "DMI_CPU0_PCH_RX_C_DN<6>")
	)
	(segment
		(start 343.91854 -85.509862)
		(end 343.91854 -81.75498)
		(width 0.13208)
		(layer "B.Cu")
		(net "DMI_CPU0_PCH_RX_C_DN<6>")
	)
	(segment
		(start 347.74632 -64.722756)
		(end 347.74632 -62.883034)
		(width 0.13208)
		(layer "B.Cu")
		(net "DMI_CPU0_PCH_RX_C_DN<6>")
	)
	(segment
		(start 350.340676 -75.332844)
		(end 350.340676 -70.551294)
		(width 0.13208)
		(layer "B.Cu")
		(net "DMI_CPU0_PCH_RX_C_DN<6>")
	)
	(segment
		(start 349.0976 -67.984878)
		(end 347.74632 -64.722756)
		(width 0.13208)
		(layer "B.Cu")
		(net "DMI_CPU0_PCH_RX_C_DN<6>")
	)
	(segment
		(start 343.91854 -81.75498)
		(end 350.340676 -75.332844)
		(width 0.13208)
		(layer "B.Cu")
		(net "DMI_CPU0_PCH_RX_C_DN<6>")
	)
	(segment
		(start 347.60408 -60.009532)
		(end 346.629228 -59.03468)
		(width 0.13208)
		(layer "B.Cu")
		(net "DMI_CPU0_PCH_RX_C_DN<6>")
	)
	(segment
		(start 349.0976 -68.240402)
		(end 349.0976 -67.984878)
		(width 0.13208)
		(layer "B.Cu")
		(net "DMI_CPU0_PCH_RX_C_DN<6>")
	)
	(segment
		(start 347.80728 -61.290454)
		(end 347.60408 -60.799726)
		(width 0.13208)
		(layer "B.Cu")
		(net "DMI_CPU0_PCH_RX_C_DN<6>")
	)
	(segment
		(start 347.80728 -62.735968)
		(end 347.80728 -61.290454)
		(width 0.13208)
		(layer "B.Cu")
		(net "DMI_CPU0_PCH_RX_C_DN<6>")
	)
	(segment
		(start 346.629228 -59.03468)
		(end 346.629228 -58.571638)
		(width 0.13208)
		(layer "B.Cu")
		(net "DMI_CPU0_PCH_RX_C_DN<6>")
	)
	(segment
		(start 350.340676 -70.551294)
		(end 349.589852 -69.428106)
		(width 0.13208)
		(layer "B.Cu")
		(net "DMI_CPU0_PCH_RX_C_DN<6>")
	)
	(segment
		(start 347.60408 -60.799726)
		(end 347.60408 -60.009532)
		(width 0.13208)
		(layer "B.Cu")
		(net "DMI_CPU0_PCH_RX_C_DN<6>")
	)
	(segment
		(start 364.37443 -218.707716)
		(end 364.37443 -218.692222)
		(width 0.0889)
		(layer "In6.Cu")
		(net "DMI_CPU0_PCH_RX_C_DN<6>")
	)
	(segment
		(start 360.707432 -222.437198)
		(end 360.722164 -222.445834)
		(width 0.0889)
		(layer "In6.Cu")
		(net "DMI_CPU0_PCH_RX_C_DN<6>")
	)
	(segment
		(start 363.619034 -219.997528)
		(end 363.621574 -219.996004)
		(width 0.0889)
		(layer "In6.Cu")
		(net "DMI_CPU0_PCH_RX_C_DN<6>")
	)
	(segment
		(start 364.560358 -218.368626)
		(end 364.561882 -218.367864)
		(width 0.0889)
		(layer "In6.Cu")
		(net "DMI_CPU0_PCH_RX_C_DN<6>")
	)
	(segment
		(start 358.014016 -228.188012)
		(end 358.038146 -228.098858)
		(width 0.0889)
		(layer "In6.Cu")
		(net "DMI_CPU0_PCH_RX_C_DN<6>")
	)
	(segment
		(start 364.083346 -219.18676)
		(end 364.092236 -219.18168)
		(width 0.0889)
		(layer "In6.Cu")
		(net "DMI_CPU0_PCH_RX_C_DN<6>")
	)
	(segment
		(start 362.495084 -221.957646)
		(end 362.495084 -221.94774)
		(width 0.0889)
		(layer "In6.Cu")
		(net "DMI_CPU0_PCH_RX_C_DN<6>")
	)
	(segment
		(start 364.552992 -218.372944)
		(end 364.560358 -218.368626)
		(width 0.0889)
		(layer "In6.Cu")
		(net "DMI_CPU0_PCH_RX_C_DN<6>")
	)
	(segment
		(start 358.17048 -228.45903)
		(end 358.014016 -228.188012)
		(width 0.0889)
		(layer "In6.Cu")
		(net "DMI_CPU0_PCH_RX_C_DN<6>")
	)
	(segment
		(start 366.287558 -211.654898)
		(end 366.329468 -211.612988)
		(width 0.0889)
		(layer "In6.Cu")
		(net "DMI_CPU0_PCH_RX_C_DN<6>")
	)
	(segment
		(start 375.787412 -195.944744)
		(end 382.239012 -186.73064)
		(width 0.14732)
		(layer "In6.Cu")
		(net "DMI_CPU0_PCH_RX_C_DN<6>")
	)
	(segment
		(start 365.492792 -215.117426)
		(end 365.501682 -215.112346)
		(width 0.0889)
		(layer "In6.Cu")
		(net "DMI_CPU0_PCH_RX_C_DN<6>")
	)
	(segment
		(start 365.023146 -215.931242)
		(end 365.032036 -215.926162)
		(width 0.0889)
		(layer "In6.Cu")
		(net "DMI_CPU0_PCH_RX_C_DN<6>")
	)
	(segment
		(start 363.611668 -221.629478)
		(end 363.628178 -221.619826)
		(width 0.0889)
		(layer "In6.Cu")
		(net "DMI_CPU0_PCH_RX_C_DN<6>")
	)
	(segment
		(start 359.39222 -225.693478)
		(end 359.393236 -225.69297)
		(width 0.0889)
		(layer "In6.Cu")
		(net "DMI_CPU0_PCH_RX_C_DN<6>")
	)
	(segment
		(start 366.329468 -208.103724)
		(end 366.60328 -206.551022)
		(width 0.14732)
		(layer "In6.Cu")
		(net "DMI_CPU0_PCH_RX_C_DN<6>")
	)
	(segment
		(start 344.17381 -87.5665)
		(end 343.92616 -86.587838)
		(width 0.14732)
		(layer "In6.Cu")
		(net "DMI_CPU0_PCH_RX_C_DN<6>")
	)
	(segment
		(start 384.02895 -176.58207)
		(end 380.047754 -154.00655)
		(width 0.14732)
		(layer "In6.Cu")
		(net "DMI_CPU0_PCH_RX_C_DN<6>")
	)
	(segment
		(start 365.618268 -215.022684)
		(end 366.287558 -214.352632)
		(width 0.0889)
		(layer "In6.Cu")
		(net "DMI_CPU0_PCH_RX_C_DN<6>")
	)
	(segment
		(start 360.145584 -222.780098)
		(end 360.145584 -222.761556)
		(width 0.0889)
		(layer "In6.Cu")
		(net "DMI_CPU0_PCH_RX_C_DN<6>")
	)
	(segment
		(start 358.265984 -227.659184)
		(end 358.265984 -227.64496)
		(width 0.0889)
		(layer "In6.Cu")
		(net "DMI_CPU0_PCH_RX_C_DN<6>")
	)
	(segment
		(start 364.561882 -216.739978)
		(end 364.562644 -216.73947)
		(width 0.0889)
		(layer "In6.Cu")
		(net "DMI_CPU0_PCH_RX_C_DN<6>")
	)
	(segment
		(start 358.923082 -226.506786)
		(end 358.923844 -226.506278)
		(width 0.0889)
		(layer "In6.Cu")
		(net "DMI_CPU0_PCH_RX_C_DN<6>")
	)
	(segment
		(start 380.047754 -154.00655)
		(end 344.17381 -87.5665)
		(width 0.14732)
		(layer "In6.Cu")
		(net "DMI_CPU0_PCH_RX_C_DN<6>")
	)
	(segment
		(start 363.904784 -219.515944)
		(end 363.904784 -219.506038)
		(width 0.0889)
		(layer "In6.Cu")
		(net "DMI_CPU0_PCH_RX_C_DN<6>")
	)
	(segment
		(start 363.904784 -221.133924)
		(end 363.904784 -221.115382)
		(width 0.0889)
		(layer "In6.Cu")
		(net "DMI_CPU0_PCH_RX_C_DN<6>")
	)
	(segment
		(start 343.92616 -86.106762)
		(end 344.2208 -85.812122)
		(width 0.14732)
		(layer "In6.Cu")
		(net "DMI_CPU0_PCH_RX_C_DN<6>")
	)
	(segment
		(start 382.239012 -186.73064)
		(end 384.02895 -176.58207)
		(width 0.14732)
		(layer "In6.Cu")
		(net "DMI_CPU0_PCH_RX_C_DN<6>")
	)
	(segment
		(start 363.621574 -219.996004)
		(end 363.622336 -219.995496)
		(width 0.0889)
		(layer "In6.Cu")
		(net "DMI_CPU0_PCH_RX_C_DN<6>")
	)
	(segment
		(start 358.923844 -226.506278)
		(end 358.929178 -226.50323)
		(width 0.0889)
		(layer "In6.Cu")
		(net "DMI_CPU0_PCH_RX_C_DN<6>")
	)
	(segment
		(start 364.562644 -218.367356)
		(end 364.567978 -218.364308)
		(width 0.0889)
		(layer "In6.Cu")
		(net "DMI_CPU0_PCH_RX_C_DN<6>")
	)
	(segment
		(start 358.444546 -227.325682)
		(end 358.453436 -227.320602)
		(width 0.0889)
		(layer "In6.Cu")
		(net "DMI_CPU0_PCH_RX_C_DN<6>")
	)
	(segment
		(start 364.844584 -217.878406)
		(end 364.844584 -217.864182)
		(width 0.0889)
		(layer "In6.Cu")
		(net "DMI_CPU0_PCH_RX_C_DN<6>")
	)
	(segment
		(start 343.92616 -86.587838)
		(end 343.92616 -86.106762)
		(width 0.14732)
		(layer "In6.Cu")
		(net "DMI_CPU0_PCH_RX_C_DN<6>")
	)
	(segment
		(start 359.384346 -224.070164)
		(end 359.393236 -224.065084)
		(width 0.0889)
		(layer "In6.Cu")
		(net "DMI_CPU0_PCH_RX_C_DN<6>")
	)
	(segment
		(start 363.613446 -220.000576)
		(end 363.619034 -219.997528)
		(width 0.0889)
		(layer "In6.Cu")
		(net "DMI_CPU0_PCH_RX_C_DN<6>")
	)
	(segment
		(start 362.673646 -221.628462)
		(end 362.682536 -221.623382)
		(width 0.0889)
		(layer "In6.Cu")
		(net "DMI_CPU0_PCH_RX_C_DN<6>")
	)
	(segment
		(start 366.287558 -214.352632)
		(end 366.287558 -211.654898)
		(width 0.0889)
		(layer "In6.Cu")
		(net "DMI_CPU0_PCH_RX_C_DN<6>")
	)
	(segment
		(start 359.384346 -225.69805)
		(end 359.39222 -225.693478)
		(width 0.0889)
		(layer "In6.Cu")
		(net "DMI_CPU0_PCH_RX_C_DN<6>")
	)
	(segment
		(start 365.31423 -215.452198)
		(end 365.31423 -215.436704)
		(width 0.0889)
		(layer "In6.Cu")
		(net "DMI_CPU0_PCH_RX_C_DN<6>")
	)
	(segment
		(start 359.854246 -223.256348)
		(end 359.863136 -223.251268)
		(width 0.0889)
		(layer "In6.Cu")
		(net "DMI_CPU0_PCH_RX_C_DN<6>")
	)
	(segment
		(start 359.393236 -224.7138)
		(end 359.384346 -224.70872)
		(width 0.0889)
		(layer "In6.Cu")
		(net "DMI_CPU0_PCH_RX_C_DN<6>")
	)
	(segment
		(start 364.562644 -216.73947)
		(end 364.567978 -216.736422)
		(width 0.0889)
		(layer "In6.Cu")
		(net "DMI_CPU0_PCH_RX_C_DN<6>")
	)
	(segment
		(start 359.67543 -225.225356)
		(end 359.67543 -225.187764)
		(width 0.0889)
		(layer "In6.Cu")
		(net "DMI_CPU0_PCH_RX_C_DN<6>")
	)
	(segment
		(start 359.393236 -224.065084)
		(end 359.399332 -224.061528)
		(width 0.0889)
		(layer "In6.Cu")
		(net "DMI_CPU0_PCH_RX_C_DN<6>")
	)
	(segment
		(start 366.60328 -206.551022)
		(end 372.339108 -198.359268)
		(width 0.14732)
		(layer "In6.Cu")
		(net "DMI_CPU0_PCH_RX_C_DN<6>")
	)
	(segment
		(start 358.735884 -226.84105)
		(end 358.735884 -226.822508)
		(width 0.0889)
		(layer "In6.Cu")
		(net "DMI_CPU0_PCH_RX_C_DN<6>")
	)
	(segment
		(start 364.374684 -217.072972)
		(end 364.374684 -217.0557)
		(width 0.0889)
		(layer "In6.Cu")
		(net "DMI_CPU0_PCH_RX_C_DN<6>")
	)
	(segment
		(start 366.329468 -211.59089)
		(end 366.329468 -208.103724)
		(width 0.14732)
		(layer "In6.Cu")
		(net "DMI_CPU0_PCH_RX_C_DN<6>")
	)
	(segment
		(start 360.324146 -222.442278)
		(end 360.333036 -222.437198)
		(width 0.0889)
		(layer "In6.Cu")
		(net "DMI_CPU0_PCH_RX_C_DN<6>")
	)
	(segment
		(start 363.621574 -220.643704)
		(end 363.613446 -220.639132)
		(width 0.0889)
		(layer "In6.Cu")
		(net "DMI_CPU0_PCH_RX_C_DN<6>")
	)
	(segment
		(start 372.339108 -198.359268)
		(end 375.787412 -195.944744)
		(width 0.14732)
		(layer "In6.Cu")
		(net "DMI_CPU0_PCH_RX_C_DN<6>")
	)
	(segment
		(start 364.561882 -218.367864)
		(end 364.562644 -218.367356)
		(width 0.0889)
		(layer "In6.Cu")
		(net "DMI_CPU0_PCH_RX_C_DN<6>")
	)
	(segment
		(start 366.329468 -211.612988)
		(end 366.329468 -211.59089)
		(width 0.0889)
		(layer "In6.Cu")
		(net "DMI_CPU0_PCH_RX_C_DN<6>")
	)
	(segment
		(start 363.622336 -220.644212)
		(end 363.621574 -220.643704)
		(width 0.0889)
		(layer "In6.Cu")
		(net "DMI_CPU0_PCH_RX_C_DN<6>")
	)
	(arc
		(start 358.453436 -227.320602)
		(mid 358.657771 -227.117997)
		(end 358.735884 -226.84105)
		(width 0.0889)
		(layer "In6.Cu")
		(net "DMI_CPU0_PCH_RX_C_DN<6>")
	)
	(arc
		(start 360.333036 -222.437198)
		(mid 360.520234 -222.387055)
		(end 360.707432 -222.437198)
		(width 0.0889)
		(layer "In6.Cu")
		(net "DMI_CPU0_PCH_RX_C_DN<6>")
	)
	(arc
		(start 359.384346 -224.70872)
		(mid 359.20587 -224.389442)
		(end 359.384346 -224.070164)
		(width 0.0889)
		(layer "In6.Cu")
		(net "DMI_CPU0_PCH_RX_C_DN<6>")
	)
	(arc
		(start 359.863136 -223.251268)
		(mid 360.065422 -223.052287)
		(end 360.145584 -222.780098)
		(width 0.0889)
		(layer "In6.Cu")
		(net "DMI_CPU0_PCH_RX_C_DN<6>")
	)
	(arc
		(start 359.206038 -226.002596)
		(mid 359.257092 -225.828016)
		(end 359.384346 -225.69805)
		(width 0.0889)
		(layer "In6.Cu")
		(net "DMI_CPU0_PCH_RX_C_DN<6>")
	)
	(arc
		(start 364.567978 -216.736422)
		(mid 364.770565 -216.530071)
		(end 364.844584 -216.25052)
		(width 0.0889)
		(layer "In6.Cu")
		(net "DMI_CPU0_PCH_RX_C_DN<6>")
	)
	(arc
		(start 365.032036 -215.926162)
		(mid 365.234859 -215.725931)
		(end 365.31423 -215.452198)
		(width 0.0889)
		(layer "In6.Cu")
		(net "DMI_CPU0_PCH_RX_C_DN<6>")
	)
	(arc
		(start 360.722164 -222.445834)
		(mid 360.998639 -222.513154)
		(end 361.272836 -222.437198)
		(width 0.0889)
		(layer "In6.Cu")
		(net "DMI_CPU0_PCH_RX_C_DN<6>")
	)
	(arc
		(start 358.038146 -228.098858)
		(mid 358.046718 -228.092335)
		(end 358.055164 -228.08565)
		(width 0.0889)
		(layer "In6.Cu")
		(net "DMI_CPU0_PCH_RX_C_DN<6>")
	)
	(arc
		(start 358.929178 -226.50323)
		(mid 359.131765 -226.296879)
		(end 359.205784 -226.017328)
		(width 0.0889)
		(layer "In6.Cu")
		(net "DMI_CPU0_PCH_RX_C_DN<6>")
	)
	(arc
		(start 363.904784 -219.506038)
		(mid 363.952463 -219.323138)
		(end 364.083346 -219.18676)
		(width 0.0889)
		(layer "In6.Cu")
		(net "DMI_CPU0_PCH_RX_C_DN<6>")
	)
	(arc
		(start 361.272836 -222.437198)
		(mid 361.460034 -222.387055)
		(end 361.647232 -222.437198)
		(width 0.0889)
		(layer "In6.Cu")
		(net "DMI_CPU0_PCH_RX_C_DN<6>")
	)
	(arc
		(start 359.675684 -223.575626)
		(mid 359.723363 -223.392726)
		(end 359.854246 -223.256348)
		(width 0.0889)
		(layer "In6.Cu")
		(net "DMI_CPU0_PCH_RX_C_DN<6>")
	)
	(arc
		(start 364.561882 -217.388694)
		(mid 364.426949 -217.25534)
		(end 364.374684 -217.072972)
		(width 0.0889)
		(layer "In6.Cu")
		(net "DMI_CPU0_PCH_RX_C_DN<6>")
	)
	(arc
		(start 365.501682 -215.112346)
		(mid 365.562902 -215.071322)
		(end 365.618268 -215.022684)
		(width 0.0889)
		(layer "In6.Cu")
		(net "DMI_CPU0_PCH_RX_C_DN<6>")
	)
	(arc
		(start 364.567978 -218.364308)
		(mid 364.770565 -218.157957)
		(end 364.844584 -217.878406)
		(width 0.0889)
		(layer "In6.Cu")
		(net "DMI_CPU0_PCH_RX_C_DN<6>")
	)
	(arc
		(start 364.844584 -216.25052)
		(mid 364.892263 -216.06762)
		(end 365.023146 -215.931242)
		(width 0.0889)
		(layer "In6.Cu")
		(net "DMI_CPU0_PCH_RX_C_DN<6>")
	)
	(arc
		(start 364.092236 -219.18168)
		(mid 364.295059 -218.981449)
		(end 364.37443 -218.707716)
		(width 0.0889)
		(layer "In6.Cu")
		(net "DMI_CPU0_PCH_RX_C_DN<6>")
	)
	(arc
		(start 363.056932 -221.623382)
		(mid 363.333491 -221.699125)
		(end 363.611668 -221.629478)
		(width 0.0889)
		(layer "In6.Cu")
		(net "DMI_CPU0_PCH_RX_C_DN<6>")
	)
	(arc
		(start 363.628178 -221.619826)
		(mid 363.830765 -221.413475)
		(end 363.904784 -221.133924)
		(width 0.0889)
		(layer "In6.Cu")
		(net "DMI_CPU0_PCH_RX_C_DN<6>")
	)
	(arc
		(start 362.212636 -222.437198)
		(mid 362.416971 -222.234593)
		(end 362.495084 -221.957646)
		(width 0.0889)
		(layer "In6.Cu")
		(net "DMI_CPU0_PCH_RX_C_DN<6>")
	)
	(arc
		(start 364.374684 -217.0557)
		(mid 364.426954 -216.873335)
		(end 364.561882 -216.739978)
		(width 0.0889)
		(layer "In6.Cu")
		(net "DMI_CPU0_PCH_RX_C_DN<6>")
	)
	(arc
		(start 361.647232 -222.437198)
		(mid 361.929934 -222.512974)
		(end 362.212636 -222.437198)
		(width 0.0889)
		(layer "In6.Cu")
		(net "DMI_CPU0_PCH_RX_C_DN<6>")
	)
	(arc
		(start 365.31423 -215.436704)
		(mid 365.361909 -215.253804)
		(end 365.492792 -215.117426)
		(width 0.0889)
		(layer "In6.Cu")
		(net "DMI_CPU0_PCH_RX_C_DN<6>")
	)
	(arc
		(start 359.67543 -225.187764)
		(mid 359.59606 -224.91403)
		(end 359.393236 -224.7138)
		(width 0.0889)
		(layer "In6.Cu")
		(net "DMI_CPU0_PCH_RX_C_DN<6>")
	)
	(arc
		(start 363.613446 -220.639132)
		(mid 363.434849 -220.319854)
		(end 363.613446 -220.000576)
		(width 0.0889)
		(layer "In6.Cu")
		(net "DMI_CPU0_PCH_RX_C_DN<6>")
	)
	(arc
		(start 359.393236 -225.69297)
		(mid 359.594518 -225.495483)
		(end 359.67543 -225.225356)
		(width 0.0889)
		(layer "In6.Cu")
		(net "DMI_CPU0_PCH_RX_C_DN<6>")
	)
	(arc
		(start 359.399332 -224.061528)
		(mid 359.601745 -223.855115)
		(end 359.675684 -223.575626)
		(width 0.0889)
		(layer "In6.Cu")
		(net "DMI_CPU0_PCH_RX_C_DN<6>")
	)
	(arc
		(start 358.055164 -228.08565)
		(mid 358.207595 -227.895668)
		(end 358.265984 -227.659184)
		(width 0.0889)
		(layer "In6.Cu")
		(net "DMI_CPU0_PCH_RX_C_DN<6>")
	)
	(arc
		(start 362.682536 -221.623382)
		(mid 362.869734 -221.573239)
		(end 363.056932 -221.623382)
		(width 0.0889)
		(layer "In6.Cu")
		(net "DMI_CPU0_PCH_RX_C_DN<6>")
	)
	(arc
		(start 364.844584 -217.864182)
		(mid 364.765365 -217.589497)
		(end 364.561882 -217.388694)
		(width 0.0889)
		(layer "In6.Cu")
		(net "DMI_CPU0_PCH_RX_C_DN<6>")
	)
	(arc
		(start 359.205784 -226.017328)
		(mid 359.205836 -226.009961)
		(end 359.206038 -226.002596)
		(width 0.0889)
		(layer "In6.Cu")
		(net "DMI_CPU0_PCH_RX_C_DN<6>")
	)
	(arc
		(start 358.265984 -227.64496)
		(mid 358.313663 -227.46206)
		(end 358.444546 -227.325682)
		(width 0.0889)
		(layer "In6.Cu")
		(net "DMI_CPU0_PCH_RX_C_DN<6>")
	)
	(arc
		(start 362.495084 -221.94774)
		(mid 362.542763 -221.76484)
		(end 362.673646 -221.628462)
		(width 0.0889)
		(layer "In6.Cu")
		(net "DMI_CPU0_PCH_RX_C_DN<6>")
	)
	(arc
		(start 358.735884 -226.822508)
		(mid 358.788154 -226.640143)
		(end 358.923082 -226.506786)
		(width 0.0889)
		(layer "In6.Cu")
		(net "DMI_CPU0_PCH_RX_C_DN<6>")
	)
	(arc
		(start 364.37443 -218.692222)
		(mid 364.422109 -218.509322)
		(end 364.552992 -218.372944)
		(width 0.0889)
		(layer "In6.Cu")
		(net "DMI_CPU0_PCH_RX_C_DN<6>")
	)
	(arc
		(start 360.145584 -222.761556)
		(mid 360.193263 -222.578656)
		(end 360.324146 -222.442278)
		(width 0.0889)
		(layer "In6.Cu")
		(net "DMI_CPU0_PCH_RX_C_DN<6>")
	)
	(arc
		(start 363.904784 -221.115382)
		(mid 363.824622 -220.843193)
		(end 363.622336 -220.644212)
		(width 0.0889)
		(layer "In6.Cu")
		(net "DMI_CPU0_PCH_RX_C_DN<6>")
	)
	(arc
		(start 363.622336 -219.995496)
		(mid 363.826671 -219.792891)
		(end 363.904784 -219.515944)
		(width 0.0889)
		(layer "In6.Cu")
		(net "DMI_CPU0_PCH_RX_C_DN<6>")
	)
	(segment
		(start 356.761034 -228.180646)
		(end 356.761034 -227.64496)
		(width 0.13208)
		(layer "F.Cu")
		(net "DMI_CPU0_PCH_RX_C_DN<5>")
	)
	(segment
		(start 356.76078 -228.1809)
		(end 356.761034 -228.180646)
		(width 0.13208)
		(layer "F.Cu")
		(net "DMI_CPU0_PCH_RX_C_DN<5>")
	)
	(segment
		(start 342.299036 -83.258914)
		(end 342.299036 -81.560162)
		(width 0.13208)
		(layer "B.Cu")
		(net "DMI_CPU0_PCH_RX_C_DN<5>")
	)
	(segment
		(start 346.465906 -64.354964)
		(end 346.4687 -64.354964)
		(width 0.13208)
		(layer "B.Cu")
		(net "DMI_CPU0_PCH_RX_C_DN<5>")
	)
	(segment
		(start 342.601296 -83.561174)
		(end 342.299036 -83.258914)
		(width 0.13208)
		(layer "B.Cu")
		(net "DMI_CPU0_PCH_RX_C_DN<5>")
	)
	(segment
		(start 346.136722 -64.684148)
		(end 346.465906 -64.354964)
		(width 0.13208)
		(layer "B.Cu")
		(net "DMI_CPU0_PCH_RX_C_DN<5>")
	)
	(segment
		(start 346.136722 -65.644014)
		(end 346.136722 -64.684148)
		(width 0.13208)
		(layer "B.Cu")
		(net "DMI_CPU0_PCH_RX_C_DN<5>")
	)
	(segment
		(start 342.299036 -81.560162)
		(end 349.057976 -74.801222)
		(width 0.13208)
		(layer "B.Cu")
		(net "DMI_CPU0_PCH_RX_C_DN<5>")
	)
	(segment
		(start 349.057976 -70.84441)
		(end 346.59697 -67.160648)
		(width 0.13208)
		(layer "B.Cu")
		(net "DMI_CPU0_PCH_RX_C_DN<5>")
	)
	(segment
		(start 349.057976 -74.801222)
		(end 349.057976 -70.84441)
		(width 0.13208)
		(layer "B.Cu")
		(net "DMI_CPU0_PCH_RX_C_DN<5>")
	)
	(segment
		(start 346.59697 -67.160648)
		(end 346.136722 -65.644014)
		(width 0.13208)
		(layer "B.Cu")
		(net "DMI_CPU0_PCH_RX_C_DN<5>")
	)
	(segment
		(start 365.736886 -206.056484)
		(end 371.465094 -197.876414)
		(width 0.14732)
		(layer "In6.Cu")
		(net "DMI_CPU0_PCH_RX_C_DN<5>")
	)
	(segment
		(start 365.336836 -210.983068)
		(end 365.336836 -208.32826)
		(width 0.14732)
		(layer "In6.Cu")
		(net "DMI_CPU0_PCH_RX_C_DN<5>")
	)
	(segment
		(start 375.106438 -195.326762)
		(end 381.445262 -186.273694)
		(width 0.14732)
		(layer "In6.Cu")
		(net "DMI_CPU0_PCH_RX_C_DN<5>")
	)
	(segment
		(start 371.465094 -197.876414)
		(end 373.245888 -196.629528)
		(width 0.14732)
		(layer "In6.Cu")
		(net "DMI_CPU0_PCH_RX_C_DN<5>")
	)
	(segment
		(start 342.761824 -88.24087)
		(end 342.306656 -86.465664)
		(width 0.14732)
		(layer "In6.Cu")
		(net "DMI_CPU0_PCH_RX_C_DN<5>")
	)
	(segment
		(start 358.735884 -223.585532)
		(end 358.735884 -223.56699)
		(width 0.0889)
		(layer "In6.Cu")
		(net "DMI_CPU0_PCH_RX_C_DN<5>")
	)
	(segment
		(start 362.671868 -220.001592)
		(end 362.683044 -219.994988)
		(width 0.0889)
		(layer "In6.Cu")
		(net "DMI_CPU0_PCH_RX_C_DN<5>")
	)
	(segment
		(start 363.143546 -219.18676)
		(end 363.152436 -219.18168)
		(width 0.0889)
		(layer "In6.Cu")
		(net "DMI_CPU0_PCH_RX_C_DN<5>")
	)
	(segment
		(start 360.894884 -221.133924)
		(end 360.894884 -221.149418)
		(width 0.0889)
		(layer "In6.Cu")
		(net "DMI_CPU0_PCH_RX_C_DN<5>")
	)
	(segment
		(start 363.622844 -218.367356)
		(end 363.628178 -218.364308)
		(width 0.0889)
		(layer "In6.Cu")
		(net "DMI_CPU0_PCH_RX_C_DN<5>")
	)
	(segment
		(start 342.306656 -86.465664)
		(end 342.306656 -83.855814)
		(width 0.14732)
		(layer "In6.Cu")
		(net "DMI_CPU0_PCH_RX_C_DN<5>")
	)
	(segment
		(start 381.445262 -186.273694)
		(end 383.101342 -176.88306)
		(width 0.14732)
		(layer "In6.Cu")
		(net "DMI_CPU0_PCH_RX_C_DN<5>")
	)
	(segment
		(start 363.621574 -217.388186)
		(end 363.613446 -217.383614)
		(width 0.0889)
		(layer "In6.Cu")
		(net "DMI_CPU0_PCH_RX_C_DN<5>")
	)
	(segment
		(start 361.742736 -220.644212)
		(end 361.741974 -220.643704)
		(width 0.0889)
		(layer "In6.Cu")
		(net "DMI_CPU0_PCH_RX_C_DN<5>")
	)
	(segment
		(start 359.205784 -222.77578)
		(end 359.205784 -222.761556)
		(width 0.0889)
		(layer "In6.Cu")
		(net "DMI_CPU0_PCH_RX_C_DN<5>")
	)
	(segment
		(start 358.265984 -226.027234)
		(end 358.265984 -226.017328)
		(width 0.0889)
		(layer "In6.Cu")
		(net "DMI_CPU0_PCH_RX_C_DN<5>")
	)
	(segment
		(start 359.863644 -221.622874)
		(end 359.868978 -221.619826)
		(width 0.0889)
		(layer "In6.Cu")
		(net "DMI_CPU0_PCH_RX_C_DN<5>")
	)
	(segment
		(start 363.613446 -216.745058)
		(end 363.628432 -216.736422)
		(width 0.0889)
		(layer "In6.Cu")
		(net "DMI_CPU0_PCH_RX_C_DN<5>")
	)
	(segment
		(start 364.374684 -215.452198)
		(end 364.374684 -215.368124)
		(width 0.0889)
		(layer "In6.Cu")
		(net "DMI_CPU0_PCH_RX_C_DN<5>")
	)
	(segment
		(start 359.862882 -221.623382)
		(end 359.863644 -221.622874)
		(width 0.0889)
		(layer "In6.Cu")
		(net "DMI_CPU0_PCH_RX_C_DN<5>")
	)
	(segment
		(start 357.982774 -226.507294)
		(end 357.983536 -226.506786)
		(width 0.0889)
		(layer "In6.Cu")
		(net "DMI_CPU0_PCH_RX_C_DN<5>")
	)
	(segment
		(start 365.336836 -211.005166)
		(end 365.336836 -210.983068)
		(width 0.0889)
		(layer "In6.Cu")
		(net "DMI_CPU0_PCH_RX_C_DN<5>")
	)
	(segment
		(start 342.306656 -83.855814)
		(end 342.601296 -83.561174)
		(width 0.14732)
		(layer "In6.Cu")
		(net "DMI_CPU0_PCH_RX_C_DN<5>")
	)
	(segment
		(start 362.683044 -219.994988)
		(end 362.688378 -219.99194)
		(width 0.0889)
		(layer "In6.Cu")
		(net "DMI_CPU0_PCH_RX_C_DN<5>")
	)
	(segment
		(start 358.444546 -224.070164)
		(end 358.453436 -224.065084)
		(width 0.0889)
		(layer "In6.Cu")
		(net "DMI_CPU0_PCH_RX_C_DN<5>")
	)
	(segment
		(start 363.622336 -217.388694)
		(end 363.621574 -217.388186)
		(width 0.0889)
		(layer "In6.Cu")
		(net "DMI_CPU0_PCH_RX_C_DN<5>")
	)
	(segment
		(start 358.444546 -225.69805)
		(end 358.453436 -225.69297)
		(width 0.0889)
		(layer "In6.Cu")
		(net "DMI_CPU0_PCH_RX_C_DN<5>")
	)
	(segment
		(start 365.294926 -211.047076)
		(end 365.336836 -211.005166)
		(width 0.0889)
		(layer "In6.Cu")
		(net "DMI_CPU0_PCH_RX_C_DN<5>")
	)
	(segment
		(start 363.434884 -218.702128)
		(end 363.434884 -218.683586)
		(width 0.0889)
		(layer "In6.Cu")
		(net "DMI_CPU0_PCH_RX_C_DN<5>")
	)
	(segment
		(start 364.083346 -215.931242)
		(end 364.092236 -215.926162)
		(width 0.0889)
		(layer "In6.Cu")
		(net "DMI_CPU0_PCH_RX_C_DN<5>")
	)
	(segment
		(start 379.129036 -154.515566)
		(end 342.761824 -88.24087)
		(width 0.14732)
		(layer "In6.Cu")
		(net "DMI_CPU0_PCH_RX_C_DN<5>")
	)
	(segment
		(start 361.733846 -220.000576)
		(end 361.742736 -219.995496)
		(width 0.0889)
		(layer "In6.Cu")
		(net "DMI_CPU0_PCH_RX_C_DN<5>")
	)
	(segment
		(start 361.741974 -220.643704)
		(end 361.733846 -220.639132)
		(width 0.0889)
		(layer "In6.Cu")
		(net "DMI_CPU0_PCH_RX_C_DN<5>")
	)
	(segment
		(start 357.980996 -226.50831)
		(end 357.982774 -226.507294)
		(width 0.0889)
		(layer "In6.Cu")
		(net "DMI_CPU0_PCH_RX_C_DN<5>")
	)
	(segment
		(start 358.453436 -224.7138)
		(end 358.444546 -224.70872)
		(width 0.0889)
		(layer "In6.Cu")
		(net "DMI_CPU0_PCH_RX_C_DN<5>")
	)
	(segment
		(start 356.761034 -227.64496)
		(end 356.917498 -227.373942)
		(width 0.0889)
		(layer "In6.Cu")
		(net "DMI_CPU0_PCH_RX_C_DN<5>")
	)
	(segment
		(start 383.101342 -176.88306)
		(end 382.966722 -176.273968)
		(width 0.14732)
		(layer "In6.Cu")
		(net "DMI_CPU0_PCH_RX_C_DN<5>")
	)
	(segment
		(start 363.622082 -218.367864)
		(end 363.622844 -218.367356)
		(width 0.0889)
		(layer "In6.Cu")
		(net "DMI_CPU0_PCH_RX_C_DN<5>")
	)
	(segment
		(start 358.73563 -225.225356)
		(end 358.73563 -225.187764)
		(width 0.0889)
		(layer "In6.Cu")
		(net "DMI_CPU0_PCH_RX_C_DN<5>")
	)
	(segment
		(start 357.974646 -226.511866)
		(end 357.980996 -226.50831)
		(width 0.0889)
		(layer "In6.Cu")
		(net "DMI_CPU0_PCH_RX_C_DN<5>")
	)
	(segment
		(start 359.675684 -221.957646)
		(end 359.675684 -221.939104)
		(width 0.0889)
		(layer "In6.Cu")
		(net "DMI_CPU0_PCH_RX_C_DN<5>")
	)
	(segment
		(start 364.44174 -215.206326)
		(end 365.294926 -214.35314)
		(width 0.0889)
		(layer "In6.Cu")
		(net "DMI_CPU0_PCH_RX_C_DN<5>")
	)
	(segment
		(start 365.294926 -214.35314)
		(end 365.294926 -211.047076)
		(width 0.0889)
		(layer "In6.Cu")
		(net "DMI_CPU0_PCH_RX_C_DN<5>")
	)
	(segment
		(start 356.917498 -227.373942)
		(end 357.006398 -227.35032)
		(width 0.0889)
		(layer "In6.Cu")
		(net "DMI_CPU0_PCH_RX_C_DN<5>")
	)
	(segment
		(start 359.384346 -222.442278)
		(end 359.393236 -222.437198)
		(width 0.0889)
		(layer "In6.Cu")
		(net "DMI_CPU0_PCH_RX_C_DN<5>")
	)
	(segment
		(start 365.336836 -208.32826)
		(end 365.736886 -206.056484)
		(width 0.14732)
		(layer "In6.Cu")
		(net "DMI_CPU0_PCH_RX_C_DN<5>")
	)
	(segment
		(start 382.966722 -176.273968)
		(end 379.129036 -154.515566)
		(width 0.14732)
		(layer "In6.Cu")
		(net "DMI_CPU0_PCH_RX_C_DN<5>")
	)
	(segment
		(start 373.245888 -196.629528)
		(end 375.106438 -195.326762)
		(width 0.14732)
		(layer "In6.Cu")
		(net "DMI_CPU0_PCH_RX_C_DN<5>")
	)
	(arc
		(start 358.453436 -225.69297)
		(mid 358.654718 -225.495483)
		(end 358.73563 -225.225356)
		(width 0.0889)
		(layer "In6.Cu")
		(net "DMI_CPU0_PCH_RX_C_DN<5>")
	)
	(arc
		(start 363.434884 -218.683586)
		(mid 363.487154 -218.501221)
		(end 363.622082 -218.367864)
		(width 0.0889)
		(layer "In6.Cu")
		(net "DMI_CPU0_PCH_RX_C_DN<5>")
	)
	(arc
		(start 357.006398 -227.35032)
		(mid 357.016265 -227.354479)
		(end 357.02621 -227.358448)
		(width 0.0889)
		(layer "In6.Cu")
		(net "DMI_CPU0_PCH_RX_C_DN<5>")
	)
	(arc
		(start 364.092236 -215.926162)
		(mid 364.295234 -215.725993)
		(end 364.374684 -215.452198)
		(width 0.0889)
		(layer "In6.Cu")
		(net "DMI_CPU0_PCH_RX_C_DN<5>")
	)
	(arc
		(start 363.628178 -218.364308)
		(mid 363.905085 -217.874797)
		(end 363.622336 -217.388694)
		(width 0.0889)
		(layer "In6.Cu")
		(net "DMI_CPU0_PCH_RX_C_DN<5>")
	)
	(arc
		(start 361.733846 -220.639132)
		(mid 361.555249 -220.319854)
		(end 361.733846 -220.000576)
		(width 0.0889)
		(layer "In6.Cu")
		(net "DMI_CPU0_PCH_RX_C_DN<5>")
	)
	(arc
		(start 364.374684 -215.368124)
		(mid 364.392104 -215.280545)
		(end 364.44174 -215.206326)
		(width 0.0889)
		(layer "In6.Cu")
		(net "DMI_CPU0_PCH_RX_C_DN<5>")
	)
	(arc
		(start 358.266238 -226.002596)
		(mid 358.317292 -225.828016)
		(end 358.444546 -225.69805)
		(width 0.0889)
		(layer "In6.Cu")
		(net "DMI_CPU0_PCH_RX_C_DN<5>")
	)
	(arc
		(start 360.894884 -221.149418)
		(mid 361.749411 -221.619615)
		(end 361.742736 -220.644212)
		(width 0.0889)
		(layer "In6.Cu")
		(net "DMI_CPU0_PCH_RX_C_DN<5>")
	)
	(arc
		(start 363.904784 -216.25052)
		(mid 363.952463 -216.06762)
		(end 364.083346 -215.931242)
		(width 0.0889)
		(layer "In6.Cu")
		(net "DMI_CPU0_PCH_RX_C_DN<5>")
	)
	(arc
		(start 359.205784 -222.761556)
		(mid 359.253463 -222.578656)
		(end 359.384346 -222.442278)
		(width 0.0889)
		(layer "In6.Cu")
		(net "DMI_CPU0_PCH_RX_C_DN<5>")
	)
	(arc
		(start 358.444546 -224.70872)
		(mid 358.265828 -224.389442)
		(end 358.444546 -224.070164)
		(width 0.0889)
		(layer "In6.Cu")
		(net "DMI_CPU0_PCH_RX_C_DN<5>")
	)
	(arc
		(start 358.923082 -223.251268)
		(mid 359.126563 -223.050464)
		(end 359.205784 -222.77578)
		(width 0.0889)
		(layer "In6.Cu")
		(net "DMI_CPU0_PCH_RX_C_DN<5>")
	)
	(arc
		(start 357.02621 -227.358448)
		(mid 357.277738 -227.394629)
		(end 357.519732 -227.317046)
		(width 0.0889)
		(layer "In6.Cu")
		(net "DMI_CPU0_PCH_RX_C_DN<5>")
	)
	(arc
		(start 363.613446 -217.383614)
		(mid 363.434849 -217.064336)
		(end 363.613446 -216.745058)
		(width 0.0889)
		(layer "In6.Cu")
		(net "DMI_CPU0_PCH_RX_C_DN<5>")
	)
	(arc
		(start 362.117132 -219.995496)
		(mid 362.393691 -220.071239)
		(end 362.671868 -220.001592)
		(width 0.0889)
		(layer "In6.Cu")
		(net "DMI_CPU0_PCH_RX_C_DN<5>")
	)
	(arc
		(start 360.145584 -221.133924)
		(mid 360.520234 -220.759274)
		(end 360.894884 -221.133924)
		(width 0.0889)
		(layer "In6.Cu")
		(net "DMI_CPU0_PCH_RX_C_DN<5>")
	)
	(arc
		(start 363.628432 -216.736422)
		(mid 363.830845 -216.530009)
		(end 363.904784 -216.25052)
		(width 0.0889)
		(layer "In6.Cu")
		(net "DMI_CPU0_PCH_RX_C_DN<5>")
	)
	(arc
		(start 359.675684 -221.939104)
		(mid 359.727954 -221.756739)
		(end 359.862882 -221.623382)
		(width 0.0889)
		(layer "In6.Cu")
		(net "DMI_CPU0_PCH_RX_C_DN<5>")
	)
	(arc
		(start 363.152436 -219.18168)
		(mid 363.356771 -218.979075)
		(end 363.434884 -218.702128)
		(width 0.0889)
		(layer "In6.Cu")
		(net "DMI_CPU0_PCH_RX_C_DN<5>")
	)
	(arc
		(start 362.964984 -219.506038)
		(mid 363.012663 -219.323138)
		(end 363.143546 -219.18676)
		(width 0.0889)
		(layer "In6.Cu")
		(net "DMI_CPU0_PCH_RX_C_DN<5>")
	)
	(arc
		(start 358.73563 -225.187764)
		(mid 358.65626 -224.91403)
		(end 358.453436 -224.7138)
		(width 0.0889)
		(layer "In6.Cu")
		(net "DMI_CPU0_PCH_RX_C_DN<5>")
	)
	(arc
		(start 358.735884 -223.56699)
		(mid 358.788154 -223.384625)
		(end 358.923082 -223.251268)
		(width 0.0889)
		(layer "In6.Cu")
		(net "DMI_CPU0_PCH_RX_C_DN<5>")
	)
	(arc
		(start 357.519732 -227.317046)
		(mid 357.722145 -227.110633)
		(end 357.796084 -226.831144)
		(width 0.0889)
		(layer "In6.Cu")
		(net "DMI_CPU0_PCH_RX_C_DN<5>")
	)
	(arc
		(start 361.742736 -219.995496)
		(mid 361.929934 -219.945353)
		(end 362.117132 -219.995496)
		(width 0.0889)
		(layer "In6.Cu")
		(net "DMI_CPU0_PCH_RX_C_DN<5>")
	)
	(arc
		(start 362.688378 -219.99194)
		(mid 362.890965 -219.785589)
		(end 362.964984 -219.506038)
		(width 0.0889)
		(layer "In6.Cu")
		(net "DMI_CPU0_PCH_RX_C_DN<5>")
	)
	(arc
		(start 357.796084 -226.831144)
		(mid 357.843763 -226.648244)
		(end 357.974646 -226.511866)
		(width 0.0889)
		(layer "In6.Cu")
		(net "DMI_CPU0_PCH_RX_C_DN<5>")
	)
	(arc
		(start 359.393236 -222.437198)
		(mid 359.597571 -222.234593)
		(end 359.675684 -221.957646)
		(width 0.0889)
		(layer "In6.Cu")
		(net "DMI_CPU0_PCH_RX_C_DN<5>")
	)
	(arc
		(start 358.265984 -226.017328)
		(mid 358.266036 -226.009961)
		(end 358.266238 -226.002596)
		(width 0.0889)
		(layer "In6.Cu")
		(net "DMI_CPU0_PCH_RX_C_DN<5>")
	)
	(arc
		(start 358.453436 -224.065084)
		(mid 358.657771 -223.862479)
		(end 358.735884 -223.585532)
		(width 0.0889)
		(layer "In6.Cu")
		(net "DMI_CPU0_PCH_RX_C_DN<5>")
	)
	(arc
		(start 357.983536 -226.506786)
		(mid 358.187871 -226.304181)
		(end 358.265984 -226.027234)
		(width 0.0889)
		(layer "In6.Cu")
		(net "DMI_CPU0_PCH_RX_C_DN<5>")
	)
	(arc
		(start 359.868978 -221.619826)
		(mid 360.071565 -221.413475)
		(end 360.145584 -221.133924)
		(width 0.0889)
		(layer "In6.Cu")
		(net "DMI_CPU0_PCH_RX_C_DN<5>")
	)
	(segment
		(start 356.29088 -228.994716)
		(end 356.29088 -228.45903)
		(width 0.13208)
		(layer "F.Cu")
		(net "DMI_CPU0_PCH_RX_C_DN<4>")
	)
	(segment
		(start 356.291134 -228.99497)
		(end 356.29088 -228.994716)
		(width 0.13208)
		(layer "F.Cu")
		(net "DMI_CPU0_PCH_RX_C_DN<4>")
	)
	(segment
		(start 340.421214 -81.661762)
		(end 340.723474 -81.964022)
		(width 0.13208)
		(layer "B.Cu")
		(net "DMI_CPU0_PCH_RX_C_DN<4>")
	)
	(segment
		(start 346.291916 -75.104498)
		(end 340.421214 -80.9752)
		(width 0.13208)
		(layer "B.Cu")
		(net "DMI_CPU0_PCH_RX_C_DN<4>")
	)
	(segment
		(start 344.443812 -68.061586)
		(end 346.291916 -72.528938)
		(width 0.13208)
		(layer "B.Cu")
		(net "DMI_CPU0_PCH_RX_C_DN<4>")
	)
	(segment
		(start 340.421214 -80.9752)
		(end 340.421214 -81.661762)
		(width 0.13208)
		(layer "B.Cu")
		(net "DMI_CPU0_PCH_RX_C_DN<4>")
	)
	(segment
		(start 344.443812 -62.63386)
		(end 344.443812 -68.061586)
		(width 0.13208)
		(layer "B.Cu")
		(net "DMI_CPU0_PCH_RX_C_DN<4>")
	)
	(segment
		(start 346.291916 -72.528938)
		(end 346.291916 -75.104498)
		(width 0.13208)
		(layer "B.Cu")
		(net "DMI_CPU0_PCH_RX_C_DN<4>")
	)
	(segment
		(start 344.754708 -62.322964)
		(end 344.443812 -62.63386)
		(width 0.13208)
		(layer "B.Cu")
		(net "DMI_CPU0_PCH_RX_C_DN<4>")
	)
	(segment
		(start 357.049578 -226.50323)
		(end 357.047038 -226.504754)
		(width 0.0889)
		(layer "In6.Cu")
		(net "DMI_CPU0_PCH_RX_C_DN<4>")
	)
	(segment
		(start 362.964984 -216.241884)
		(end 362.964984 -216.25052)
		(width 0.0889)
		(layer "In6.Cu")
		(net "DMI_CPU0_PCH_RX_C_DN<4>")
	)
	(segment
		(start 374.471946 -194.667124)
		(end 370.830348 -197.216776)
		(width 0.14732)
		(layer "In6.Cu")
		(net "DMI_CPU0_PCH_RX_C_DN<4>")
	)
	(segment
		(start 357.504746 -224.70872)
		(end 357.513636 -224.7138)
		(width 0.0889)
		(layer "In6.Cu")
		(net "DMI_CPU0_PCH_RX_C_DN<4>")
	)
	(segment
		(start 357.047038 -226.504754)
		(end 357.044244 -226.506278)
		(width 0.0889)
		(layer "In6.Cu")
		(net "DMI_CPU0_PCH_RX_C_DN<4>")
	)
	(segment
		(start 357.513636 -224.065084)
		(end 357.504746 -224.070164)
		(width 0.0889)
		(layer "In6.Cu")
		(net "DMI_CPU0_PCH_RX_C_DN<4>")
	)
	(segment
		(start 356.573836 -227.320602)
		(end 356.564946 -227.325682)
		(width 0.0889)
		(layer "In6.Cu")
		(net "DMI_CPU0_PCH_RX_C_DN<4>")
	)
	(segment
		(start 358.735884 -221.94774)
		(end 358.735884 -221.957646)
		(width 0.0889)
		(layer "In6.Cu")
		(net "DMI_CPU0_PCH_RX_C_DN<4>")
	)
	(segment
		(start 357.513636 -225.69297)
		(end 357.51262 -225.693478)
		(width 0.0889)
		(layer "In6.Cu")
		(net "DMI_CPU0_PCH_RX_C_DN<4>")
	)
	(segment
		(start 357.79583 -225.187764)
		(end 357.79583 -225.225356)
		(width 0.0889)
		(layer "In6.Cu")
		(net "DMI_CPU0_PCH_RX_C_DN<4>")
	)
	(segment
		(start 358.453436 -222.437198)
		(end 358.452674 -222.437706)
		(width 0.0889)
		(layer "In6.Cu")
		(net "DMI_CPU0_PCH_RX_C_DN<4>")
	)
	(segment
		(start 364.4392 -208.22031)
		(end 364.4392 -212.610954)
		(width 0.14732)
		(layer "In6.Cu")
		(net "DMI_CPU0_PCH_RX_C_DN<4>")
	)
	(segment
		(start 362.682536 -218.367864)
		(end 362.681774 -218.368372)
		(width 0.0889)
		(layer "In6.Cu")
		(net "DMI_CPU0_PCH_RX_C_DN<4>")
	)
	(segment
		(start 364.880398 -205.714092)
		(end 364.4392 -208.22031)
		(width 0.14732)
		(layer "In6.Cu")
		(net "DMI_CPU0_PCH_RX_C_DN<4>")
	)
	(segment
		(start 357.044244 -226.506278)
		(end 357.043482 -226.506786)
		(width 0.0889)
		(layer "In6.Cu")
		(net "DMI_CPU0_PCH_RX_C_DN<4>")
	)
	(segment
		(start 364.39729 -212.674962)
		(end 364.39729 -214.191596)
		(width 0.0889)
		(layer "In6.Cu")
		(net "DMI_CPU0_PCH_RX_C_DN<4>")
	)
	(segment
		(start 357.51262 -225.693478)
		(end 357.504746 -225.69805)
		(width 0.0889)
		(layer "In6.Cu")
		(net "DMI_CPU0_PCH_RX_C_DN<4>")
	)
	(segment
		(start 381.848106 -175.100234)
		(end 380.783846 -181.131464)
		(width 0.14732)
		(layer "In6.Cu")
		(net "DMI_CPU0_PCH_RX_C_DN<4>")
	)
	(segment
		(start 358.735884 -220.311218)
		(end 358.735884 -220.32849)
		(width 0.0889)
		(layer "In6.Cu")
		(net "DMI_CPU0_PCH_RX_C_DN<4>")
	)
	(segment
		(start 362.681774 -218.368372)
		(end 362.673646 -218.372944)
		(width 0.0889)
		(layer "In6.Cu")
		(net "DMI_CPU0_PCH_RX_C_DN<4>")
	)
	(segment
		(start 359.863136 -219.995496)
		(end 359.852722 -220.001592)
		(width 0.0889)
		(layer "In6.Cu")
		(net "DMI_CPU0_PCH_RX_C_DN<4>")
	)
	(segment
		(start 361.272836 -219.18168)
		(end 361.263946 -219.18676)
		(width 0.0889)
		(layer "In6.Cu")
		(net "DMI_CPU0_PCH_RX_C_DN<4>")
	)
	(segment
		(start 357.983536 -223.251268)
		(end 357.974646 -223.256348)
		(width 0.0889)
		(layer "In6.Cu")
		(net "DMI_CPU0_PCH_RX_C_DN<4>")
	)
	(segment
		(start 364.4392 -212.610954)
		(end 364.4392 -212.633052)
		(width 0.0889)
		(layer "In6.Cu")
		(net "DMI_CPU0_PCH_RX_C_DN<4>")
	)
	(segment
		(start 360.807 -219.992956)
		(end 360.804968 -219.994226)
		(width 0.0889)
		(layer "In6.Cu")
		(net "DMI_CPU0_PCH_RX_C_DN<4>")
	)
	(segment
		(start 356.134416 -228.188012)
		(end 356.29088 -228.45903)
		(width 0.0889)
		(layer "In6.Cu")
		(net "DMI_CPU0_PCH_RX_C_DN<4>")
	)
	(segment
		(start 360.804968 -219.994226)
		(end 360.802682 -219.995496)
		(width 0.0889)
		(layer "In6.Cu")
		(net "DMI_CPU0_PCH_RX_C_DN<4>")
	)
	(segment
		(start 362.688378 -216.736422)
		(end 362.682282 -216.739978)
		(width 0.0889)
		(layer "In6.Cu")
		(net "DMI_CPU0_PCH_RX_C_DN<4>")
	)
	(segment
		(start 358.265984 -222.761556)
		(end 358.265984 -222.780098)
		(width 0.0889)
		(layer "In6.Cu")
		(net "DMI_CPU0_PCH_RX_C_DN<4>")
	)
	(segment
		(start 362.495084 -217.0557)
		(end 362.495084 -217.072972)
		(width 0.0889)
		(layer "In6.Cu")
		(net "DMI_CPU0_PCH_RX_C_DN<4>")
	)
	(segment
		(start 379.717808 -187.174632)
		(end 374.471946 -194.667124)
		(width 0.14732)
		(layer "In6.Cu")
		(net "DMI_CPU0_PCH_RX_C_DN<4>")
	)
	(segment
		(start 358.452674 -222.437706)
		(end 358.444546 -222.442278)
		(width 0.0889)
		(layer "In6.Cu")
		(net "DMI_CPU0_PCH_RX_C_DN<4>")
	)
	(segment
		(start 357.519732 -224.061528)
		(end 357.513636 -224.065084)
		(width 0.0889)
		(layer "In6.Cu")
		(net "DMI_CPU0_PCH_RX_C_DN<4>")
	)
	(segment
		(start 362.964984 -217.864182)
		(end 362.964984 -217.888312)
		(width 0.0889)
		(layer "In6.Cu")
		(net "DMI_CPU0_PCH_RX_C_DN<4>")
	)
	(segment
		(start 356.856284 -226.822508)
		(end 356.856284 -226.84105)
		(width 0.0889)
		(layer "In6.Cu")
		(net "DMI_CPU0_PCH_RX_C_DN<4>")
	)
	(segment
		(start 340.723474 -81.964022)
		(end 340.428834 -82.258662)
		(width 0.14732)
		(layer "In6.Cu")
		(net "DMI_CPU0_PCH_RX_C_DN<4>")
	)
	(segment
		(start 364.294674 -214.4395)
		(end 363.541056 -215.193118)
		(width 0.0889)
		(layer "In6.Cu")
		(net "DMI_CPU0_PCH_RX_C_DN<4>")
	)
	(segment
		(start 370.830348 -197.216776)
		(end 367.855246 -201.465434)
		(width 0.14732)
		(layer "In6.Cu")
		(net "DMI_CPU0_PCH_RX_C_DN<4>")
	)
	(segment
		(start 358.923336 -221.623382)
		(end 358.914446 -221.628462)
		(width 0.0889)
		(layer "In6.Cu")
		(net "DMI_CPU0_PCH_RX_C_DN<4>")
	)
	(segment
		(start 378.298964 -154.982418)
		(end 381.848106 -175.100234)
		(width 0.14732)
		(layer "In6.Cu")
		(net "DMI_CPU0_PCH_RX_C_DN<4>")
	)
	(segment
		(start 341.859362 -89.884504)
		(end 378.298964 -154.982418)
		(width 0.14732)
		(layer "In6.Cu")
		(net "DMI_CPU0_PCH_RX_C_DN<4>")
	)
	(segment
		(start 356.386384 -227.64496)
		(end 356.386384 -227.659184)
		(width 0.0889)
		(layer "In6.Cu")
		(net "DMI_CPU0_PCH_RX_C_DN<4>")
	)
	(segment
		(start 364.4392 -212.633052)
		(end 364.39729 -212.674962)
		(width 0.0889)
		(layer "In6.Cu")
		(net "DMI_CPU0_PCH_RX_C_DN<4>")
	)
	(segment
		(start 340.428834 -82.258662)
		(end 340.428834 -84.399882)
		(width 0.14732)
		(layer "In6.Cu")
		(net "DMI_CPU0_PCH_RX_C_DN<4>")
	)
	(segment
		(start 360.802682 -219.995496)
		(end 360.792268 -220.001592)
		(width 0.0889)
		(layer "In6.Cu")
		(net "DMI_CPU0_PCH_RX_C_DN<4>")
	)
	(segment
		(start 362.495084 -218.692222)
		(end 362.495084 -218.702128)
		(width 0.0889)
		(layer "In6.Cu")
		(net "DMI_CPU0_PCH_RX_C_DN<4>")
	)
	(segment
		(start 356.158546 -228.098858)
		(end 356.134416 -228.188012)
		(width 0.0889)
		(layer "In6.Cu")
		(net "DMI_CPU0_PCH_RX_C_DN<4>")
	)
	(segment
		(start 359.205784 -221.1197)
		(end 359.205784 -221.14383)
		(width 0.0889)
		(layer "In6.Cu")
		(net "DMI_CPU0_PCH_RX_C_DN<4>")
	)
	(segment
		(start 360.808778 -219.99194)
		(end 360.807 -219.992956)
		(width 0.0889)
		(layer "In6.Cu")
		(net "DMI_CPU0_PCH_RX_C_DN<4>")
	)
	(segment
		(start 367.855246 -201.465434)
		(end 364.880398 -205.714092)
		(width 0.14732)
		(layer "In6.Cu")
		(net "DMI_CPU0_PCH_RX_C_DN<4>")
	)
	(segment
		(start 340.428834 -84.399882)
		(end 341.859362 -89.884504)
		(width 0.14732)
		(layer "In6.Cu")
		(net "DMI_CPU0_PCH_RX_C_DN<4>")
	)
	(segment
		(start 380.783846 -181.131464)
		(end 379.717808 -187.174632)
		(width 0.14732)
		(layer "In6.Cu")
		(net "DMI_CPU0_PCH_RX_C_DN<4>")
	)
	(arc
		(start 358.735884 -221.957646)
		(mid 358.657773 -222.234595)
		(end 358.453436 -222.437198)
		(width 0.0889)
		(layer "In6.Cu")
		(net "DMI_CPU0_PCH_RX_C_DN<4>")
	)
	(arc
		(start 360.237532 -219.995496)
		(mid 360.050334 -219.945353)
		(end 359.863136 -219.995496)
		(width 0.0889)
		(layer "In6.Cu")
		(net "DMI_CPU0_PCH_RX_C_DN<4>")
	)
	(arc
		(start 357.504746 -224.070164)
		(mid 357.32627 -224.389442)
		(end 357.504746 -224.70872)
		(width 0.0889)
		(layer "In6.Cu")
		(net "DMI_CPU0_PCH_RX_C_DN<4>")
	)
	(arc
		(start 362.964984 -216.25052)
		(mid 362.890993 -216.530086)
		(end 362.688378 -216.736422)
		(width 0.0889)
		(layer "In6.Cu")
		(net "DMI_CPU0_PCH_RX_C_DN<4>")
	)
	(arc
		(start 356.386384 -227.659184)
		(mid 356.328039 -227.895689)
		(end 356.175564 -228.08565)
		(width 0.0889)
		(layer "In6.Cu")
		(net "DMI_CPU0_PCH_RX_C_DN<4>")
	)
	(arc
		(start 363.541056 -215.193118)
		(mid 363.465516 -215.310484)
		(end 363.43463 -215.44661)
		(width 0.0889)
		(layer "In6.Cu")
		(net "DMI_CPU0_PCH_RX_C_DN<4>")
	)
	(arc
		(start 359.205784 -221.14383)
		(mid 359.127673 -221.420779)
		(end 358.923336 -221.623382)
		(width 0.0889)
		(layer "In6.Cu")
		(net "DMI_CPU0_PCH_RX_C_DN<4>")
	)
	(arc
		(start 358.735884 -220.32849)
		(mid 358.788154 -220.510855)
		(end 358.923082 -220.644212)
		(width 0.0889)
		(layer "In6.Cu")
		(net "DMI_CPU0_PCH_RX_C_DN<4>")
	)
	(arc
		(start 356.564946 -227.325682)
		(mid 356.434032 -227.462042)
		(end 356.386384 -227.64496)
		(width 0.0889)
		(layer "In6.Cu")
		(net "DMI_CPU0_PCH_RX_C_DN<4>")
	)
	(arc
		(start 362.212636 -219.18168)
		(mid 361.929934 -219.257456)
		(end 361.647232 -219.18168)
		(width 0.0889)
		(layer "In6.Cu")
		(net "DMI_CPU0_PCH_RX_C_DN<4>")
	)
	(arc
		(start 359.852722 -220.001592)
		(mid 359.57429 -220.071438)
		(end 359.297478 -219.995496)
		(width 0.0889)
		(layer "In6.Cu")
		(net "DMI_CPU0_PCH_RX_C_DN<4>")
	)
	(arc
		(start 364.39729 -214.191596)
		(mid 364.370638 -214.325763)
		(end 364.294674 -214.4395)
		(width 0.0889)
		(layer "In6.Cu")
		(net "DMI_CPU0_PCH_RX_C_DN<4>")
	)
	(arc
		(start 361.263946 -219.18676)
		(mid 361.133032 -219.32312)
		(end 361.085384 -219.506038)
		(width 0.0889)
		(layer "In6.Cu")
		(net "DMI_CPU0_PCH_RX_C_DN<4>")
	)
	(arc
		(start 363.152182 -215.926162)
		(mid 363.017249 -216.059516)
		(end 362.964984 -216.241884)
		(width 0.0889)
		(layer "In6.Cu")
		(net "DMI_CPU0_PCH_RX_C_DN<4>")
	)
	(arc
		(start 362.682282 -216.739978)
		(mid 362.547349 -216.873332)
		(end 362.495084 -217.0557)
		(width 0.0889)
		(layer "In6.Cu")
		(net "DMI_CPU0_PCH_RX_C_DN<4>")
	)
	(arc
		(start 362.682282 -217.388694)
		(mid 362.885763 -217.589498)
		(end 362.964984 -217.864182)
		(width 0.0889)
		(layer "In6.Cu")
		(net "DMI_CPU0_PCH_RX_C_DN<4>")
	)
	(arc
		(start 356.175564 -228.08565)
		(mid 356.167118 -228.092335)
		(end 356.158546 -228.098858)
		(width 0.0889)
		(layer "In6.Cu")
		(net "DMI_CPU0_PCH_RX_C_DN<4>")
	)
	(arc
		(start 359.297478 -219.995496)
		(mid 359.11028 -219.945353)
		(end 358.923082 -219.995496)
		(width 0.0889)
		(layer "In6.Cu")
		(net "DMI_CPU0_PCH_RX_C_DN<4>")
	)
	(arc
		(start 363.43463 -215.44661)
		(mid 363.356519 -215.723559)
		(end 363.152182 -215.926162)
		(width 0.0889)
		(layer "In6.Cu")
		(net "DMI_CPU0_PCH_RX_C_DN<4>")
	)
	(arc
		(start 357.974646 -223.256348)
		(mid 357.843732 -223.392708)
		(end 357.796084 -223.575626)
		(width 0.0889)
		(layer "In6.Cu")
		(net "DMI_CPU0_PCH_RX_C_DN<4>")
	)
	(arc
		(start 361.085384 -219.506038)
		(mid 361.011393 -219.785604)
		(end 360.808778 -219.99194)
		(width 0.0889)
		(layer "In6.Cu")
		(net "DMI_CPU0_PCH_RX_C_DN<4>")
	)
	(arc
		(start 362.495084 -217.072972)
		(mid 362.547354 -217.255337)
		(end 362.682282 -217.388694)
		(width 0.0889)
		(layer "In6.Cu")
		(net "DMI_CPU0_PCH_RX_C_DN<4>")
	)
	(arc
		(start 357.326184 -226.017328)
		(mid 357.252193 -226.296894)
		(end 357.049578 -226.50323)
		(width 0.0889)
		(layer "In6.Cu")
		(net "DMI_CPU0_PCH_RX_C_DN<4>")
	)
	(arc
		(start 358.923082 -220.644212)
		(mid 359.126563 -220.845016)
		(end 359.205784 -221.1197)
		(width 0.0889)
		(layer "In6.Cu")
		(net "DMI_CPU0_PCH_RX_C_DN<4>")
	)
	(arc
		(start 361.647232 -219.18168)
		(mid 361.460034 -219.131537)
		(end 361.272836 -219.18168)
		(width 0.0889)
		(layer "In6.Cu")
		(net "DMI_CPU0_PCH_RX_C_DN<4>")
	)
	(arc
		(start 357.504746 -225.69805)
		(mid 357.377492 -225.828016)
		(end 357.326438 -226.002596)
		(width 0.0889)
		(layer "In6.Cu")
		(net "DMI_CPU0_PCH_RX_C_DN<4>")
	)
	(arc
		(start 358.265984 -222.780098)
		(mid 358.185822 -223.052287)
		(end 357.983536 -223.251268)
		(width 0.0889)
		(layer "In6.Cu")
		(net "DMI_CPU0_PCH_RX_C_DN<4>")
	)
	(arc
		(start 356.856284 -226.84105)
		(mid 356.778173 -227.117999)
		(end 356.573836 -227.320602)
		(width 0.0889)
		(layer "In6.Cu")
		(net "DMI_CPU0_PCH_RX_C_DN<4>")
	)
	(arc
		(start 362.673646 -218.372944)
		(mid 362.542732 -218.509304)
		(end 362.495084 -218.692222)
		(width 0.0889)
		(layer "In6.Cu")
		(net "DMI_CPU0_PCH_RX_C_DN<4>")
	)
	(arc
		(start 362.495084 -218.702128)
		(mid 362.416973 -218.979077)
		(end 362.212636 -219.18168)
		(width 0.0889)
		(layer "In6.Cu")
		(net "DMI_CPU0_PCH_RX_C_DN<4>")
	)
	(arc
		(start 358.923082 -219.995496)
		(mid 358.788149 -220.12885)
		(end 358.735884 -220.311218)
		(width 0.0889)
		(layer "In6.Cu")
		(net "DMI_CPU0_PCH_RX_C_DN<4>")
	)
	(arc
		(start 357.326438 -226.002596)
		(mid 357.326241 -226.009961)
		(end 357.326184 -226.017328)
		(width 0.0889)
		(layer "In6.Cu")
		(net "DMI_CPU0_PCH_RX_C_DN<4>")
	)
	(arc
		(start 360.792268 -220.001592)
		(mid 360.51409 -220.071315)
		(end 360.237532 -219.995496)
		(width 0.0889)
		(layer "In6.Cu")
		(net "DMI_CPU0_PCH_RX_C_DN<4>")
	)
	(arc
		(start 357.513636 -224.7138)
		(mid 357.716459 -224.914031)
		(end 357.79583 -225.187764)
		(width 0.0889)
		(layer "In6.Cu")
		(net "DMI_CPU0_PCH_RX_C_DN<4>")
	)
	(arc
		(start 357.796084 -223.575626)
		(mid 357.722168 -223.855128)
		(end 357.519732 -224.061528)
		(width 0.0889)
		(layer "In6.Cu")
		(net "DMI_CPU0_PCH_RX_C_DN<4>")
	)
	(arc
		(start 357.043482 -226.506786)
		(mid 356.908549 -226.64014)
		(end 356.856284 -226.822508)
		(width 0.0889)
		(layer "In6.Cu")
		(net "DMI_CPU0_PCH_RX_C_DN<4>")
	)
	(arc
		(start 358.914446 -221.628462)
		(mid 358.783532 -221.764822)
		(end 358.735884 -221.94774)
		(width 0.0889)
		(layer "In6.Cu")
		(net "DMI_CPU0_PCH_RX_C_DN<4>")
	)
	(arc
		(start 358.444546 -222.442278)
		(mid 358.313632 -222.578638)
		(end 358.265984 -222.761556)
		(width 0.0889)
		(layer "In6.Cu")
		(net "DMI_CPU0_PCH_RX_C_DN<4>")
	)
	(arc
		(start 362.964984 -217.888312)
		(mid 362.886873 -218.165261)
		(end 362.682536 -218.367864)
		(width 0.0889)
		(layer "In6.Cu")
		(net "DMI_CPU0_PCH_RX_C_DN<4>")
	)
	(arc
		(start 357.79583 -225.225356)
		(mid 357.714919 -225.495484)
		(end 357.513636 -225.69297)
		(width 0.0889)
		(layer "In6.Cu")
		(net "DMI_CPU0_PCH_RX_C_DN<4>")
	)
	(segment
		(start 354.88118 -228.1809)
		(end 354.881434 -228.180646)
		(width 0.13208)
		(layer "F.Cu")
		(net "DMI_CPU0_PCH_RX_C_DN<3>")
	)
	(segment
		(start 354.881434 -228.180646)
		(end 354.881434 -227.64496)
		(width 0.13208)
		(layer "F.Cu")
		(net "DMI_CPU0_PCH_RX_C_DN<3>")
	)
	(segment
		(start 342.838532 -64.682624)
		(end 342.838532 -68.20281)
		(width 0.13208)
		(layer "B.Cu")
		(net "DMI_CPU0_PCH_RX_C_DN<3>")
	)
	(segment
		(start 342.946736 -73.575672)
		(end 342.946736 -76.256388)
		(width 0.13208)
		(layer "B.Cu")
		(net "DMI_CPU0_PCH_RX_C_DN<3>")
	)
	(segment
		(start 338.82457 -80.378554)
		(end 338.82457 -84.182204)
		(width 0.13208)
		(layer "B.Cu")
		(net "DMI_CPU0_PCH_RX_C_DN<3>")
	)
	(segment
		(start 342.946736 -76.256388)
		(end 338.82457 -80.378554)
		(width 0.13208)
		(layer "B.Cu")
		(net "DMI_CPU0_PCH_RX_C_DN<3>")
	)
	(segment
		(start 343.571576 -71.91248)
		(end 343.512648 -72.210422)
		(width 0.13208)
		(layer "B.Cu")
		(net "DMI_CPU0_PCH_RX_C_DN<3>")
	)
	(segment
		(start 338.82457 -84.182204)
		(end 339.12683 -84.484464)
		(width 0.13208)
		(layer "B.Cu")
		(net "DMI_CPU0_PCH_RX_C_DN<3>")
	)
	(segment
		(start 343.571576 -69.972682)
		(end 343.571576 -71.91248)
		(width 0.13208)
		(layer "B.Cu")
		(net "DMI_CPU0_PCH_RX_C_DN<3>")
	)
	(segment
		(start 343.166192 -64.354964)
		(end 342.838532 -64.682624)
		(width 0.13208)
		(layer "B.Cu")
		(net "DMI_CPU0_PCH_RX_C_DN<3>")
	)
	(segment
		(start 342.838532 -68.20281)
		(end 343.571576 -69.972682)
		(width 0.13208)
		(layer "B.Cu")
		(net "DMI_CPU0_PCH_RX_C_DN<3>")
	)
	(segment
		(start 343.512648 -72.210422)
		(end 342.946736 -73.575672)
		(width 0.13208)
		(layer "B.Cu")
		(net "DMI_CPU0_PCH_RX_C_DN<3>")
	)
	(segment
		(start 362.49483 -215.4301)
		(end 362.495084 -215.436704)
		(width 0.0889)
		(layer "In6.Cu")
		(net "DMI_CPU0_PCH_RX_C_DN<3>")
	)
	(segment
		(start 357.97998 -221.625414)
		(end 357.976932 -221.627192)
		(width 0.0889)
		(layer "In6.Cu")
		(net "DMI_CPU0_PCH_RX_C_DN<3>")
	)
	(segment
		(start 363.297978 -211.657438)
		(end 363.297978 -214.480902)
		(width 0.0889)
		(layer "In6.Cu")
		(net "DMI_CPU0_PCH_RX_C_DN<3>")
	)
	(segment
		(start 356.103936 -226.506786)
		(end 356.103174 -226.507294)
		(width 0.0889)
		(layer "In6.Cu")
		(net "DMI_CPU0_PCH_RX_C_DN<3>")
	)
	(segment
		(start 373.861838 -194.01028)
		(end 369.685062 -196.93509)
		(width 0.14732)
		(layer "In6.Cu")
		(net "DMI_CPU0_PCH_RX_C_DN<3>")
	)
	(segment
		(start 363.297978 -214.480902)
		(end 362.63326 -215.14562)
		(width 0.0889)
		(layer "In6.Cu")
		(net "DMI_CPU0_PCH_RX_C_DN<3>")
	)
	(segment
		(start 357.982774 -219.996004)
		(end 357.980234 -219.997528)
		(width 0.0889)
		(layer "In6.Cu")
		(net "DMI_CPU0_PCH_RX_C_DN<3>")
	)
	(segment
		(start 357.982012 -221.624398)
		(end 357.97998 -221.625414)
		(width 0.0889)
		(layer "In6.Cu")
		(net "DMI_CPU0_PCH_RX_C_DN<3>")
	)
	(segment
		(start 357.326184 -222.761556)
		(end 357.326184 -222.77578)
		(width 0.0889)
		(layer "In6.Cu")
		(net "DMI_CPU0_PCH_RX_C_DN<3>")
	)
	(segment
		(start 378.87275 -186.854084)
		(end 373.861838 -194.01028)
		(width 0.14732)
		(layer "In6.Cu")
		(net "DMI_CPU0_PCH_RX_C_DN<3>")
	)
	(segment
		(start 363.339888 -208.699608)
		(end 363.339888 -211.59343)
		(width 0.14732)
		(layer "In6.Cu")
		(net "DMI_CPU0_PCH_RX_C_DN<3>")
	)
	(segment
		(start 363.339888 -211.59343)
		(end 363.339888 -211.615528)
		(width 0.0889)
		(layer "In6.Cu")
		(net "DMI_CPU0_PCH_RX_C_DN<3>")
	)
	(segment
		(start 358.838754 -219.18803)
		(end 358.827832 -219.18168)
		(width 0.0889)
		(layer "In6.Cu")
		(net "DMI_CPU0_PCH_RX_C_DN<3>")
	)
	(segment
		(start 362.025184 -217.877898)
		(end 362.025184 -217.888312)
		(width 0.0889)
		(layer "In6.Cu")
		(net "DMI_CPU0_PCH_RX_C_DN<3>")
	)
	(segment
		(start 356.573836 -225.69297)
		(end 356.57282 -225.693478)
		(width 0.0889)
		(layer "In6.Cu")
		(net "DMI_CPU0_PCH_RX_C_DN<3>")
	)
	(segment
		(start 380.839218 -175.70958)
		(end 378.87275 -186.854084)
		(width 0.14732)
		(layer "In6.Cu")
		(net "DMI_CPU0_PCH_RX_C_DN<3>")
	)
	(segment
		(start 360.802682 -218.367864)
		(end 360.801158 -218.368626)
		(width 0.0889)
		(layer "In6.Cu")
		(net "DMI_CPU0_PCH_RX_C_DN<3>")
	)
	(segment
		(start 356.564946 -224.70872)
		(end 356.573836 -224.7138)
		(width 0.0889)
		(layer "In6.Cu")
		(net "DMI_CPU0_PCH_RX_C_DN<3>")
	)
	(segment
		(start 357.983536 -221.623382)
		(end 357.982012 -221.624398)
		(width 0.0889)
		(layer "In6.Cu")
		(net "DMI_CPU0_PCH_RX_C_DN<3>")
	)
	(segment
		(start 363.339888 -211.615528)
		(end 363.297978 -211.657438)
		(width 0.0889)
		(layer "In6.Cu")
		(net "DMI_CPU0_PCH_RX_C_DN<3>")
	)
	(segment
		(start 357.519732 -222.433642)
		(end 357.515922 -222.435928)
		(width 0.0889)
		(layer "In6.Cu")
		(net "DMI_CPU0_PCH_RX_C_DN<3>")
	)
	(segment
		(start 362.63326 -215.14562)
		(end 362.627672 -215.1507)
		(width 0.0889)
		(layer "In6.Cu")
		(net "DMI_CPU0_PCH_RX_C_DN<3>")
	)
	(segment
		(start 363.975142 -205.08976)
		(end 363.339888 -208.699608)
		(width 0.14732)
		(layer "In6.Cu")
		(net "DMI_CPU0_PCH_RX_C_DN<3>")
	)
	(segment
		(start 360.801158 -218.368626)
		(end 360.793792 -218.372944)
		(width 0.0889)
		(layer "In6.Cu")
		(net "DMI_CPU0_PCH_RX_C_DN<3>")
	)
	(segment
		(start 361.741974 -217.388186)
		(end 361.742736 -217.388694)
		(width 0.0889)
		(layer "In6.Cu")
		(net "DMI_CPU0_PCH_RX_C_DN<3>")
	)
	(segment
		(start 356.573836 -224.065084)
		(end 356.564946 -224.070164)
		(width 0.0889)
		(layer "In6.Cu")
		(net "DMI_CPU0_PCH_RX_C_DN<3>")
	)
	(segment
		(start 357.514144 -222.436944)
		(end 357.504746 -222.442278)
		(width 0.0889)
		(layer "In6.Cu")
		(net "DMI_CPU0_PCH_RX_C_DN<3>")
	)
	(segment
		(start 355.037898 -227.373942)
		(end 354.881434 -227.64496)
		(width 0.0889)
		(layer "In6.Cu")
		(net "DMI_CPU0_PCH_RX_C_DN<3>")
	)
	(segment
		(start 356.57282 -225.693478)
		(end 356.564946 -225.69805)
		(width 0.0889)
		(layer "In6.Cu")
		(net "DMI_CPU0_PCH_RX_C_DN<3>")
	)
	(segment
		(start 359.372916 -219.193364)
		(end 359.367328 -219.196412)
		(width 0.0889)
		(layer "In6.Cu")
		(net "DMI_CPU0_PCH_RX_C_DN<3>")
	)
	(segment
		(start 377.26366 -155.444444)
		(end 380.839218 -175.70958)
		(width 0.14732)
		(layer "In6.Cu")
		(net "DMI_CPU0_PCH_RX_C_DN<3>")
	)
	(segment
		(start 339.699346 -89.088976)
		(end 377.26366 -155.444444)
		(width 0.14732)
		(layer "In6.Cu")
		(net "DMI_CPU0_PCH_RX_C_DN<3>")
	)
	(segment
		(start 361.748832 -216.736422)
		(end 361.733846 -216.745058)
		(width 0.0889)
		(layer "In6.Cu")
		(net "DMI_CPU0_PCH_RX_C_DN<3>")
	)
	(segment
		(start 360.61523 -218.692222)
		(end 360.61523 -218.707716)
		(width 0.0889)
		(layer "In6.Cu")
		(net "DMI_CPU0_PCH_RX_C_DN<3>")
	)
	(segment
		(start 357.980234 -219.997528)
		(end 357.974646 -220.000576)
		(width 0.0889)
		(layer "In6.Cu")
		(net "DMI_CPU0_PCH_RX_C_DN<3>")
	)
	(segment
		(start 338.83219 -84.779104)
		(end 338.83219 -85.79739)
		(width 0.14732)
		(layer "In6.Cu")
		(net "DMI_CPU0_PCH_RX_C_DN<3>")
	)
	(segment
		(start 362.495084 -215.436704)
		(end 362.495084 -215.452198)
		(width 0.0889)
		(layer "In6.Cu")
		(net "DMI_CPU0_PCH_RX_C_DN<3>")
	)
	(segment
		(start 357.515922 -222.435928)
		(end 357.514144 -222.436944)
		(width 0.0889)
		(layer "In6.Cu")
		(net "DMI_CPU0_PCH_RX_C_DN<3>")
	)
	(segment
		(start 357.983536 -219.995496)
		(end 357.982774 -219.996004)
		(width 0.0889)
		(layer "In6.Cu")
		(net "DMI_CPU0_PCH_RX_C_DN<3>")
	)
	(segment
		(start 356.85603 -225.187764)
		(end 356.85603 -225.225356)
		(width 0.0889)
		(layer "In6.Cu")
		(net "DMI_CPU0_PCH_RX_C_DN<3>")
	)
	(segment
		(start 359.782364 -219.190316)
		(end 359.767632 -219.18168)
		(width 0.0889)
		(layer "In6.Cu")
		(net "DMI_CPU0_PCH_RX_C_DN<3>")
	)
	(segment
		(start 339.12683 -84.484464)
		(end 338.83219 -84.779104)
		(width 0.14732)
		(layer "In6.Cu")
		(net "DMI_CPU0_PCH_RX_C_DN<3>")
	)
	(segment
		(start 356.103174 -226.507294)
		(end 356.100634 -226.508818)
		(width 0.0889)
		(layer "In6.Cu")
		(net "DMI_CPU0_PCH_RX_C_DN<3>")
	)
	(segment
		(start 361.733846 -217.383614)
		(end 361.741974 -217.388186)
		(width 0.0889)
		(layer "In6.Cu")
		(net "DMI_CPU0_PCH_RX_C_DN<3>")
	)
	(segment
		(start 356.100634 -226.508818)
		(end 356.095046 -226.511866)
		(width 0.0889)
		(layer "In6.Cu")
		(net "DMI_CPU0_PCH_RX_C_DN<3>")
	)
	(segment
		(start 359.393236 -219.18168)
		(end 359.372916 -219.193364)
		(width 0.0889)
		(layer "In6.Cu")
		(net "DMI_CPU0_PCH_RX_C_DN<3>")
	)
	(segment
		(start 355.126798 -227.35032)
		(end 355.037898 -227.373942)
		(width 0.0889)
		(layer "In6.Cu")
		(net "DMI_CPU0_PCH_RX_C_DN<3>")
	)
	(segment
		(start 362.212636 -215.926162)
		(end 362.203746 -215.931242)
		(width 0.0889)
		(layer "In6.Cu")
		(net "DMI_CPU0_PCH_RX_C_DN<3>")
	)
	(segment
		(start 357.976932 -221.627192)
		(end 357.974646 -221.628462)
		(width 0.0889)
		(layer "In6.Cu")
		(net "DMI_CPU0_PCH_RX_C_DN<3>")
	)
	(segment
		(start 356.386384 -226.017328)
		(end 356.386384 -226.027234)
		(width 0.0889)
		(layer "In6.Cu")
		(net "DMI_CPU0_PCH_RX_C_DN<3>")
	)
	(segment
		(start 357.974646 -220.639132)
		(end 357.983536 -220.644212)
		(width 0.0889)
		(layer "In6.Cu")
		(net "DMI_CPU0_PCH_RX_C_DN<3>")
	)
	(segment
		(start 356.856284 -223.56699)
		(end 356.856284 -223.585532)
		(width 0.0889)
		(layer "In6.Cu")
		(net "DMI_CPU0_PCH_RX_C_DN<3>")
	)
	(segment
		(start 358.265984 -219.506038)
		(end 358.265984 -219.515944)
		(width 0.0889)
		(layer "In6.Cu")
		(net "DMI_CPU0_PCH_RX_C_DN<3>")
	)
	(segment
		(start 369.685062 -196.93509)
		(end 363.975142 -205.08976)
		(width 0.14732)
		(layer "In6.Cu")
		(net "DMI_CPU0_PCH_RX_C_DN<3>")
	)
	(segment
		(start 338.83219 -85.79739)
		(end 339.699346 -89.088976)
		(width 0.14732)
		(layer "In6.Cu")
		(net "DMI_CPU0_PCH_RX_C_DN<3>")
	)
	(arc
		(start 356.095046 -226.511866)
		(mid 355.964132 -226.648226)
		(end 355.916484 -226.831144)
		(width 0.0889)
		(layer "In6.Cu")
		(net "DMI_CPU0_PCH_RX_C_DN<3>")
	)
	(arc
		(start 357.983536 -220.644212)
		(mid 358.185974 -220.843269)
		(end 358.265984 -221.115636)
		(width 0.0889)
		(layer "In6.Cu")
		(net "DMI_CPU0_PCH_RX_C_DN<3>")
	)
	(arc
		(start 356.85603 -225.225356)
		(mid 356.775119 -225.495484)
		(end 356.573836 -225.69297)
		(width 0.0889)
		(layer "In6.Cu")
		(net "DMI_CPU0_PCH_RX_C_DN<3>")
	)
	(arc
		(start 358.266238 -221.144084)
		(mid 358.187918 -221.420898)
		(end 357.983536 -221.623382)
		(width 0.0889)
		(layer "In6.Cu")
		(net "DMI_CPU0_PCH_RX_C_DN<3>")
	)
	(arc
		(start 357.796084 -221.94774)
		(mid 357.722168 -222.227242)
		(end 357.519732 -222.433642)
		(width 0.0889)
		(layer "In6.Cu")
		(net "DMI_CPU0_PCH_RX_C_DN<3>")
	)
	(arc
		(start 357.326184 -222.77578)
		(mid 357.246965 -223.050465)
		(end 357.043482 -223.251268)
		(width 0.0889)
		(layer "In6.Cu")
		(net "DMI_CPU0_PCH_RX_C_DN<3>")
	)
	(arc
		(start 356.386638 -226.002596)
		(mid 356.386441 -226.009961)
		(end 356.386384 -226.017328)
		(width 0.0889)
		(layer "In6.Cu")
		(net "DMI_CPU0_PCH_RX_C_DN<3>")
	)
	(arc
		(start 358.827832 -219.18168)
		(mid 358.644557 -219.131557)
		(end 358.460294 -219.17787)
		(width 0.0889)
		(layer "In6.Cu")
		(net "DMI_CPU0_PCH_RX_C_DN<3>")
	)
	(arc
		(start 356.564946 -225.69805)
		(mid 356.437692 -225.828016)
		(end 356.386638 -226.002596)
		(width 0.0889)
		(layer "In6.Cu")
		(net "DMI_CPU0_PCH_RX_C_DN<3>")
	)
	(arc
		(start 355.916484 -226.831144)
		(mid 355.842568 -227.110646)
		(end 355.640132 -227.317046)
		(width 0.0889)
		(layer "In6.Cu")
		(net "DMI_CPU0_PCH_RX_C_DN<3>")
	)
	(arc
		(start 357.504746 -222.442278)
		(mid 357.373832 -222.578638)
		(end 357.326184 -222.761556)
		(width 0.0889)
		(layer "In6.Cu")
		(net "DMI_CPU0_PCH_RX_C_DN<3>")
	)
	(arc
		(start 356.856284 -223.585532)
		(mid 356.778173 -223.862481)
		(end 356.573836 -224.065084)
		(width 0.0889)
		(layer "In6.Cu")
		(net "DMI_CPU0_PCH_RX_C_DN<3>")
	)
	(arc
		(start 358.265984 -219.515944)
		(mid 358.187873 -219.792893)
		(end 357.983536 -219.995496)
		(width 0.0889)
		(layer "In6.Cu")
		(net "DMI_CPU0_PCH_RX_C_DN<3>")
	)
	(arc
		(start 360.793792 -218.372944)
		(mid 360.662878 -218.509304)
		(end 360.61523 -218.692222)
		(width 0.0889)
		(layer "In6.Cu")
		(net "DMI_CPU0_PCH_RX_C_DN<3>")
	)
	(arc
		(start 355.14661 -227.358448)
		(mid 355.136666 -227.354477)
		(end 355.126798 -227.35032)
		(width 0.0889)
		(layer "In6.Cu")
		(net "DMI_CPU0_PCH_RX_C_DN<3>")
	)
	(arc
		(start 356.386384 -226.027234)
		(mid 356.308273 -226.304183)
		(end 356.103936 -226.506786)
		(width 0.0889)
		(layer "In6.Cu")
		(net "DMI_CPU0_PCH_RX_C_DN<3>")
	)
	(arc
		(start 357.974646 -220.000576)
		(mid 357.796049 -220.319854)
		(end 357.974646 -220.639132)
		(width 0.0889)
		(layer "In6.Cu")
		(net "DMI_CPU0_PCH_RX_C_DN<3>")
	)
	(arc
		(start 362.025184 -217.888312)
		(mid 361.738182 -218.370617)
		(end 361.177078 -218.367864)
		(width 0.0889)
		(layer "In6.Cu")
		(net "DMI_CPU0_PCH_RX_C_DN<3>")
	)
	(arc
		(start 358.460294 -219.17787)
		(mid 358.318249 -219.315364)
		(end 358.265984 -219.506038)
		(width 0.0889)
		(layer "In6.Cu")
		(net "DMI_CPU0_PCH_RX_C_DN<3>")
	)
	(arc
		(start 357.974646 -221.628462)
		(mid 357.843732 -221.764822)
		(end 357.796084 -221.94774)
		(width 0.0889)
		(layer "In6.Cu")
		(net "DMI_CPU0_PCH_RX_C_DN<3>")
	)
	(arc
		(start 362.627672 -215.1507)
		(mid 362.531067 -215.27605)
		(end 362.49483 -215.4301)
		(width 0.0889)
		(layer "In6.Cu")
		(net "DMI_CPU0_PCH_RX_C_DN<3>")
	)
	(arc
		(start 359.767632 -219.18168)
		(mid 359.580434 -219.131537)
		(end 359.393236 -219.18168)
		(width 0.0889)
		(layer "In6.Cu")
		(net "DMI_CPU0_PCH_RX_C_DN<3>")
	)
	(arc
		(start 362.025184 -216.25052)
		(mid 361.951268 -216.530022)
		(end 361.748832 -216.736422)
		(width 0.0889)
		(layer "In6.Cu")
		(net "DMI_CPU0_PCH_RX_C_DN<3>")
	)
	(arc
		(start 362.203746 -215.931242)
		(mid 362.072832 -216.067602)
		(end 362.025184 -216.25052)
		(width 0.0889)
		(layer "In6.Cu")
		(net "DMI_CPU0_PCH_RX_C_DN<3>")
	)
	(arc
		(start 356.573836 -224.7138)
		(mid 356.776659 -224.914031)
		(end 356.85603 -225.187764)
		(width 0.0889)
		(layer "In6.Cu")
		(net "DMI_CPU0_PCH_RX_C_DN<3>")
	)
	(arc
		(start 360.61523 -218.707716)
		(mid 360.53586 -218.98145)
		(end 360.333036 -219.18168)
		(width 0.0889)
		(layer "In6.Cu")
		(net "DMI_CPU0_PCH_RX_C_DN<3>")
	)
	(arc
		(start 361.733846 -216.745058)
		(mid 361.555249 -217.064336)
		(end 361.733846 -217.383614)
		(width 0.0889)
		(layer "In6.Cu")
		(net "DMI_CPU0_PCH_RX_C_DN<3>")
	)
	(arc
		(start 355.640132 -227.317046)
		(mid 355.398142 -227.394669)
		(end 355.14661 -227.358448)
		(width 0.0889)
		(layer "In6.Cu")
		(net "DMI_CPU0_PCH_RX_C_DN<3>")
	)
	(arc
		(start 358.265984 -221.115636)
		(mid 358.266291 -221.129858)
		(end 358.266238 -221.144084)
		(width 0.0889)
		(layer "In6.Cu")
		(net "DMI_CPU0_PCH_RX_C_DN<3>")
	)
	(arc
		(start 357.043482 -223.251268)
		(mid 356.908549 -223.384622)
		(end 356.856284 -223.56699)
		(width 0.0889)
		(layer "In6.Cu")
		(net "DMI_CPU0_PCH_RX_C_DN<3>")
	)
	(arc
		(start 359.367328 -219.196412)
		(mid 359.101948 -219.260952)
		(end 358.838754 -219.18803)
		(width 0.0889)
		(layer "In6.Cu")
		(net "DMI_CPU0_PCH_RX_C_DN<3>")
	)
	(arc
		(start 362.495084 -215.452198)
		(mid 362.415635 -215.725994)
		(end 362.212636 -215.926162)
		(width 0.0889)
		(layer "In6.Cu")
		(net "DMI_CPU0_PCH_RX_C_DN<3>")
	)
	(arc
		(start 361.742736 -217.388694)
		(mid 361.949496 -217.595457)
		(end 362.025184 -217.877898)
		(width 0.0889)
		(layer "In6.Cu")
		(net "DMI_CPU0_PCH_RX_C_DN<3>")
	)
	(arc
		(start 356.564946 -224.070164)
		(mid 356.435657 -224.20365)
		(end 356.386384 -224.382838)
		(width 0.0889)
		(layer "In6.Cu")
		(net "DMI_CPU0_PCH_RX_C_DN<3>")
	)
	(arc
		(start 356.386384 -224.399602)
		(mid 356.436475 -224.576797)
		(end 356.564946 -224.70872)
		(width 0.0889)
		(layer "In6.Cu")
		(net "DMI_CPU0_PCH_RX_C_DN<3>")
	)
	(arc
		(start 356.386384 -224.382838)
		(mid 356.38629 -224.39122)
		(end 356.386384 -224.399602)
		(width 0.0889)
		(layer "In6.Cu")
		(net "DMI_CPU0_PCH_RX_C_DN<3>")
	)
	(arc
		(start 361.177078 -218.367864)
		(mid 360.98988 -218.317721)
		(end 360.802682 -218.367864)
		(width 0.0889)
		(layer "In6.Cu")
		(net "DMI_CPU0_PCH_RX_C_DN<3>")
	)
	(arc
		(start 360.333036 -219.18168)
		(mid 360.058837 -219.257515)
		(end 359.782364 -219.190316)
		(width 0.0889)
		(layer "In6.Cu")
		(net "DMI_CPU0_PCH_RX_C_DN<3>")
	)
	(segment
		(start 353.94138 -228.1809)
		(end 353.94138 -227.645214)
		(width 0.13208)
		(layer "F.Cu")
		(net "DMI_CPU0_PCH_RX_C_DN<2>")
	)
	(segment
		(start 353.94138 -227.645214)
		(end 353.941634 -227.64496)
		(width 0.13208)
		(layer "F.Cu")
		(net "DMI_CPU0_PCH_RX_C_DN<2>")
	)
	(segment
		(start 340.974172 -63.54572)
		(end 340.733888 -63.305436)
		(width 0.13208)
		(layer "B.Cu")
		(net "DMI_CPU0_PCH_RX_C_DN<2>")
	)
	(segment
		(start 341.298276 -75.114404)
		(end 341.298276 -73.589134)
		(width 0.13208)
		(layer "B.Cu")
		(net "DMI_CPU0_PCH_RX_C_DN<2>")
	)
	(segment
		(start 341.298276 -73.589134)
		(end 340.284816 -72.071992)
		(width 0.13208)
		(layer "B.Cu")
		(net "DMI_CPU0_PCH_RX_C_DN<2>")
	)
	(segment
		(start 336.87258 -81.968848)
		(end 336.87258 -79.5401)
		(width 0.13208)
		(layer "B.Cu")
		(net "DMI_CPU0_PCH_RX_C_DN<2>")
	)
	(segment
		(start 336.87258 -79.5401)
		(end 341.298276 -75.114404)
		(width 0.13208)
		(layer "B.Cu")
		(net "DMI_CPU0_PCH_RX_C_DN<2>")
	)
	(segment
		(start 340.733888 -62.650624)
		(end 340.406228 -62.322964)
		(width 0.13208)
		(layer "B.Cu")
		(net "DMI_CPU0_PCH_RX_C_DN<2>")
	)
	(segment
		(start 340.974172 -64.8081)
		(end 340.974172 -63.54572)
		(width 0.13208)
		(layer "B.Cu")
		(net "DMI_CPU0_PCH_RX_C_DN<2>")
	)
	(segment
		(start 341.376 -65.77838)
		(end 340.974172 -64.8081)
		(width 0.13208)
		(layer "B.Cu")
		(net "DMI_CPU0_PCH_RX_C_DN<2>")
	)
	(segment
		(start 341.376 -67.597782)
		(end 341.376 -65.77838)
		(width 0.13208)
		(layer "B.Cu")
		(net "DMI_CPU0_PCH_RX_C_DN<2>")
	)
	(segment
		(start 340.284816 -70.23227)
		(end 341.376 -67.597782)
		(width 0.13208)
		(layer "B.Cu")
		(net "DMI_CPU0_PCH_RX_C_DN<2>")
	)
	(segment
		(start 340.733888 -63.305436)
		(end 340.733888 -62.650624)
		(width 0.13208)
		(layer "B.Cu")
		(net "DMI_CPU0_PCH_RX_C_DN<2>")
	)
	(segment
		(start 340.284816 -72.071992)
		(end 340.284816 -70.23227)
		(width 0.13208)
		(layer "B.Cu")
		(net "DMI_CPU0_PCH_RX_C_DN<2>")
	)
	(segment
		(start 336.57032 -82.271108)
		(end 336.87258 -81.968848)
		(width 0.13208)
		(layer "B.Cu")
		(net "DMI_CPU0_PCH_RX_C_DN<2>")
	)
	(segment
		(start 336.86496 -82.565748)
		(end 336.57032 -82.271108)
		(width 0.14732)
		(layer "In6.Cu")
		(net "DMI_CPU0_PCH_RX_C_DN<2>")
	)
	(segment
		(start 355.539294 -224.879408)
		(end 355.538278 -224.8789)
		(width 0.0889)
		(layer "In6.Cu")
		(net "DMI_CPU0_PCH_RX_C_DN<2>")
	)
	(segment
		(start 355.256084 -224.404936)
		(end 355.256084 -224.373948)
		(width 0.0889)
		(layer "In6.Cu")
		(net "DMI_CPU0_PCH_RX_C_DN<2>")
	)
	(segment
		(start 361.917742 -213.242144)
		(end 362.015532 -213.144354)
		(width 0.0889)
		(layer "In6.Cu")
		(net "DMI_CPU0_PCH_RX_C_DN<2>")
	)
	(segment
		(start 362.016802 -213.869524)
		(end 362.016802 -213.605364)
		(width 0.0889)
		(layer "In6.Cu")
		(net "DMI_CPU0_PCH_RX_C_DN<2>")
	)
	(segment
		(start 355.72573 -223.575626)
		(end 355.72573 -223.568006)
		(width 0.0889)
		(layer "In6.Cu")
		(net "DMI_CPU0_PCH_RX_C_DN<2>")
	)
	(segment
		(start 355.538278 -223.899984)
		(end 355.539294 -223.899476)
		(width 0.0889)
		(layer "In6.Cu")
		(net "DMI_CPU0_PCH_RX_C_DN<2>")
	)
	(segment
		(start 362.016802 -213.605364)
		(end 361.917742 -213.506304)
		(width 0.0889)
		(layer "In6.Cu")
		(net "DMI_CPU0_PCH_RX_C_DN<2>")
	)
	(segment
		(start 360.707178 -216.574878)
		(end 360.716068 -216.569798)
		(width 0.0889)
		(layer "In6.Cu")
		(net "DMI_CPU0_PCH_RX_C_DN<2>")
	)
	(segment
		(start 372.958614 -193.282824)
		(end 377.661932 -186.56554)
		(width 0.14732)
		(layer "In6.Cu")
		(net "DMI_CPU0_PCH_RX_C_DN<2>")
	)
	(segment
		(start 357.973122 -217.382598)
		(end 357.983536 -217.388694)
		(width 0.0889)
		(layer "In6.Cu")
		(net "DMI_CPU0_PCH_RX_C_DN<2>")
	)
	(segment
		(start 357.426768 -218.372944)
		(end 357.418894 -218.368372)
		(width 0.0889)
		(layer "In6.Cu")
		(net "DMI_CPU0_PCH_RX_C_DN<2>")
	)
	(segment
		(start 358.265984 -217.859864)
		(end 358.265984 -217.878406)
		(width 0.0889)
		(layer "In6.Cu")
		(net "DMI_CPU0_PCH_RX_C_DN<2>")
	)
	(segment
		(start 356.008432 -223.085914)
		(end 356.017322 -223.080834)
		(width 0.0889)
		(layer "In6.Cu")
		(net "DMI_CPU0_PCH_RX_C_DN<2>")
	)
	(segment
		(start 354.098098 -227.915978)
		(end 354.17633 -227.936806)
		(width 0.0889)
		(layer "In6.Cu")
		(net "DMI_CPU0_PCH_RX_C_DN<2>")
	)
	(segment
		(start 361.177078 -215.761062)
		(end 361.185968 -215.755982)
		(width 0.0889)
		(layer "In6.Cu")
		(net "DMI_CPU0_PCH_RX_C_DN<2>")
	)
	(segment
		(start 361.724448 -214.88781)
		(end 361.724956 -214.88781)
		(width 0.0889)
		(layer "In6.Cu")
		(net "DMI_CPU0_PCH_RX_C_DN<2>")
	)
	(segment
		(start 356.949756 -221.45752)
		(end 356.957122 -221.453202)
		(width 0.0889)
		(layer "In6.Cu")
		(net "DMI_CPU0_PCH_RX_C_DN<2>")
	)
	(segment
		(start 362.015532 -212.675216)
		(end 361.973368 -212.633052)
		(width 0.0889)
		(layer "In6.Cu")
		(net "DMI_CPU0_PCH_RX_C_DN<2>")
	)
	(segment
		(start 379.514608 -176.068736)
		(end 375.978166 -156.02839)
		(width 0.14732)
		(layer "In6.Cu")
		(net "DMI_CPU0_PCH_RX_C_DN<2>")
	)
	(segment
		(start 356.478078 -222.272098)
		(end 356.486968 -222.267018)
		(width 0.0889)
		(layer "In6.Cu")
		(net "DMI_CPU0_PCH_RX_C_DN<2>")
	)
	(segment
		(start 356.957122 -220.814646)
		(end 356.948232 -220.809566)
		(width 0.0889)
		(layer "In6.Cu")
		(net "DMI_CPU0_PCH_RX_C_DN<2>")
	)
	(segment
		(start 365.580422 -200.41362)
		(end 368.278664 -196.560186)
		(width 0.14732)
		(layer "In6.Cu")
		(net "DMI_CPU0_PCH_RX_C_DN<2>")
	)
	(segment
		(start 356.957122 -219.825062)
		(end 356.957122 -219.825316)
		(width 0.0889)
		(layer "In6.Cu")
		(net "DMI_CPU0_PCH_RX_C_DN<2>")
	)
	(segment
		(start 377.661932 -186.56554)
		(end 379.514608 -176.068736)
		(width 0.14732)
		(layer "In6.Cu")
		(net "DMI_CPU0_PCH_RX_C_DN<2>")
	)
	(segment
		(start 375.978166 -156.02839)
		(end 338.190586 -90.10269)
		(width 0.14732)
		(layer "In6.Cu")
		(net "DMI_CPU0_PCH_RX_C_DN<2>")
	)
	(segment
		(start 356.948232 -221.458282)
		(end 356.949756 -221.45752)
		(width 0.0889)
		(layer "In6.Cu")
		(net "DMI_CPU0_PCH_RX_C_DN<2>")
	)
	(segment
		(start 358.444546 -218.197684)
		(end 358.453436 -218.202764)
		(width 0.0889)
		(layer "In6.Cu")
		(net "DMI_CPU0_PCH_RX_C_DN<2>")
	)
	(segment
		(start 368.278664 -196.560186)
		(end 372.958614 -193.282824)
		(width 0.14732)
		(layer "In6.Cu")
		(net "DMI_CPU0_PCH_RX_C_DN<2>")
	)
	(segment
		(start 356.942136 -219.833952)
		(end 356.957122 -219.825062)
		(width 0.0889)
		(layer "In6.Cu")
		(net "DMI_CPU0_PCH_RX_C_DN<2>")
	)
	(segment
		(start 361.917742 -213.506304)
		(end 361.917742 -213.242144)
		(width 0.0889)
		(layer "In6.Cu")
		(net "DMI_CPU0_PCH_RX_C_DN<2>")
	)
	(segment
		(start 361.917742 -213.968584)
		(end 362.016802 -213.869524)
		(width 0.0889)
		(layer "In6.Cu")
		(net "DMI_CPU0_PCH_RX_C_DN<2>")
	)
	(segment
		(start 362.016802 -214.595964)
		(end 362.016802 -214.331804)
		(width 0.0889)
		(layer "In6.Cu")
		(net "DMI_CPU0_PCH_RX_C_DN<2>")
	)
	(segment
		(start 338.190586 -90.10269)
		(end 336.86496 -85.124544)
		(width 0.14732)
		(layer "In6.Cu")
		(net "DMI_CPU0_PCH_RX_C_DN<2>")
	)
	(segment
		(start 355.062536 -226.345242)
		(end 355.077522 -226.336352)
		(width 0.0889)
		(layer "In6.Cu")
		(net "DMI_CPU0_PCH_RX_C_DN<2>")
	)
	(segment
		(start 356.66553 -220.334078)
		(end 356.66553 -220.319854)
		(width 0.0889)
		(layer "In6.Cu")
		(net "DMI_CPU0_PCH_RX_C_DN<2>")
	)
	(segment
		(start 356.195884 -222.761556)
		(end 356.195884 -222.746062)
		(width 0.0889)
		(layer "In6.Cu")
		(net "DMI_CPU0_PCH_RX_C_DN<2>")
	)
	(segment
		(start 355.538278 -225.527616)
		(end 355.547168 -225.522536)
		(width 0.0889)
		(layer "In6.Cu")
		(net "DMI_CPU0_PCH_RX_C_DN<2>")
	)
	(segment
		(start 355.539294 -223.899476)
		(end 355.547168 -223.894904)
		(width 0.0889)
		(layer "In6.Cu")
		(net "DMI_CPU0_PCH_RX_C_DN<2>")
	)
	(segment
		(start 357.135684 -217.8939)
		(end 357.135684 -217.856308)
		(width 0.0889)
		(layer "In6.Cu")
		(net "DMI_CPU0_PCH_RX_C_DN<2>")
	)
	(segment
		(start 360.42473 -217.072972)
		(end 360.42473 -217.05443)
		(width 0.0889)
		(layer "In6.Cu")
		(net "DMI_CPU0_PCH_RX_C_DN<2>")
	)
	(segment
		(start 362.875068 -204.27696)
		(end 365.580168 -200.413874)
		(width 0.14732)
		(layer "In6.Cu")
		(net "DMI_CPU0_PCH_RX_C_DN<2>")
	)
	(segment
		(start 355.077522 -226.336352)
		(end 355.077522 -226.336606)
		(width 0.0889)
		(layer "In6.Cu")
		(net "DMI_CPU0_PCH_RX_C_DN<2>")
	)
	(segment
		(start 353.941634 -227.64496)
		(end 354.098098 -227.915978)
		(width 0.0889)
		(layer "In6.Cu")
		(net "DMI_CPU0_PCH_RX_C_DN<2>")
	)
	(segment
		(start 361.724956 -214.88781)
		(end 362.016802 -214.595964)
		(width 0.0889)
		(layer "In6.Cu")
		(net "DMI_CPU0_PCH_RX_C_DN<2>")
	)
	(segment
		(start 361.917742 -214.232744)
		(end 361.917742 -213.968584)
		(width 0.0889)
		(layer "In6.Cu")
		(net "DMI_CPU0_PCH_RX_C_DN<2>")
	)
	(segment
		(start 361.973368 -212.610954)
		(end 361.973368 -209.404458)
		(width 0.14732)
		(layer "In6.Cu")
		(net "DMI_CPU0_PCH_RX_C_DN<2>")
	)
	(segment
		(start 357.418894 -219.016072)
		(end 357.426768 -219.0115)
		(width 0.0889)
		(layer "In6.Cu")
		(net "DMI_CPU0_PCH_RX_C_DN<2>")
	)
	(segment
		(start 361.36453 -215.436704)
		(end 361.36453 -215.426798)
		(width 0.0889)
		(layer "In6.Cu")
		(net "DMI_CPU0_PCH_RX_C_DN<2>")
	)
	(segment
		(start 356.94747 -221.45879)
		(end 356.948232 -221.458282)
		(width 0.0889)
		(layer "In6.Cu")
		(net "DMI_CPU0_PCH_RX_C_DN<2>")
	)
	(segment
		(start 362.015532 -213.144354)
		(end 362.015532 -212.675216)
		(width 0.0889)
		(layer "In6.Cu")
		(net "DMI_CPU0_PCH_RX_C_DN<2>")
	)
	(segment
		(start 359.015284 -217.878406)
		(end 359.015284 -217.859864)
		(width 0.0889)
		(layer "In6.Cu")
		(net "DMI_CPU0_PCH_RX_C_DN<2>")
	)
	(segment
		(start 361.973368 -209.404458)
		(end 362.875068 -204.27696)
		(width 0.14732)
		(layer "In6.Cu")
		(net "DMI_CPU0_PCH_RX_C_DN<2>")
	)
	(segment
		(start 357.417878 -219.01658)
		(end 357.418894 -219.016072)
		(width 0.0889)
		(layer "In6.Cu")
		(net "DMI_CPU0_PCH_RX_C_DN<2>")
	)
	(segment
		(start 354.78593 -226.83978)
		(end 354.78593 -226.831144)
		(width 0.0889)
		(layer "In6.Cu")
		(net "DMI_CPU0_PCH_RX_C_DN<2>")
	)
	(segment
		(start 357.418894 -218.368372)
		(end 357.417878 -218.367864)
		(width 0.0889)
		(layer "In6.Cu")
		(net "DMI_CPU0_PCH_RX_C_DN<2>")
	)
	(segment
		(start 362.016802 -214.331804)
		(end 361.917742 -214.232744)
		(width 0.0889)
		(layer "In6.Cu")
		(net "DMI_CPU0_PCH_RX_C_DN<2>")
	)
	(segment
		(start 336.86496 -85.124544)
		(end 336.86496 -82.565748)
		(width 0.14732)
		(layer "In6.Cu")
		(net "DMI_CPU0_PCH_RX_C_DN<2>")
	)
	(segment
		(start 361.973368 -212.633052)
		(end 361.973368 -212.610954)
		(width 0.0889)
		(layer "In6.Cu")
		(net "DMI_CPU0_PCH_RX_C_DN<2>")
	)
	(segment
		(start 360.89463 -216.25052)
		(end 360.89463 -216.240614)
		(width 0.0889)
		(layer "In6.Cu")
		(net "DMI_CPU0_PCH_RX_C_DN<2>")
	)
	(segment
		(start 358.827832 -218.202764)
		(end 358.836722 -218.197684)
		(width 0.0889)
		(layer "In6.Cu")
		(net "DMI_CPU0_PCH_RX_C_DN<2>")
	)
	(segment
		(start 357.135684 -219.506038)
		(end 357.135684 -219.490544)
		(width 0.0889)
		(layer "In6.Cu")
		(net "DMI_CPU0_PCH_RX_C_DN<2>")
	)
	(segment
		(start 365.580168 -200.413874)
		(end 365.580422 -200.41362)
		(width 0.14732)
		(layer "In6.Cu")
		(net "DMI_CPU0_PCH_RX_C_DN<2>")
	)
	(segment
		(start 354.316284 -227.64496)
		(end 354.316284 -227.635054)
		(width 0.0889)
		(layer "In6.Cu")
		(net "DMI_CPU0_PCH_RX_C_DN<2>")
	)
	(segment
		(start 356.942136 -221.461838)
		(end 356.94747 -221.45879)
		(width 0.0889)
		(layer "In6.Cu")
		(net "DMI_CPU0_PCH_RX_C_DN<2>")
	)
	(segment
		(start 355.256084 -226.017328)
		(end 355.256084 -225.99523)
		(width 0.0889)
		(layer "In6.Cu")
		(net "DMI_CPU0_PCH_RX_C_DN<2>")
	)
	(segment
		(start 355.547168 -224.88398)
		(end 355.539294 -224.879408)
		(width 0.0889)
		(layer "In6.Cu")
		(net "DMI_CPU0_PCH_RX_C_DN<2>")
	)
	(arc
		(start 358.836722 -218.197684)
		(mid 358.967636 -218.061324)
		(end 359.015284 -217.878406)
		(width 0.0889)
		(layer "In6.Cu")
		(net "DMI_CPU0_PCH_RX_C_DN<2>")
	)
	(arc
		(start 357.426768 -219.0115)
		(mid 357.605365 -218.692222)
		(end 357.426768 -218.372944)
		(width 0.0889)
		(layer "In6.Cu")
		(net "DMI_CPU0_PCH_RX_C_DN<2>")
	)
	(arc
		(start 359.863136 -217.388694)
		(mid 360.050334 -217.438837)
		(end 360.237532 -217.388694)
		(width 0.0889)
		(layer "In6.Cu")
		(net "DMI_CPU0_PCH_RX_C_DN<2>")
	)
	(arc
		(start 354.78593 -226.831144)
		(mid 354.859921 -226.551578)
		(end 355.062536 -226.345242)
		(width 0.0889)
		(layer "In6.Cu")
		(net "DMI_CPU0_PCH_RX_C_DN<2>")
	)
	(arc
		(start 354.316284 -227.635054)
		(mid 354.394395 -227.358105)
		(end 354.598732 -227.155502)
		(width 0.0889)
		(layer "In6.Cu")
		(net "DMI_CPU0_PCH_RX_C_DN<2>")
	)
	(arc
		(start 356.66553 -221.94774)
		(mid 356.739521 -221.668174)
		(end 356.942136 -221.461838)
		(width 0.0889)
		(layer "In6.Cu")
		(net "DMI_CPU0_PCH_RX_C_DN<2>")
	)
	(arc
		(start 355.547168 -225.522536)
		(mid 355.674422 -225.39257)
		(end 355.725476 -225.21799)
		(width 0.0889)
		(layer "In6.Cu")
		(net "DMI_CPU0_PCH_RX_C_DN<2>")
	)
	(arc
		(start 359.015284 -217.859864)
		(mid 359.095446 -217.587675)
		(end 359.297732 -217.388694)
		(width 0.0889)
		(layer "In6.Cu")
		(net "DMI_CPU0_PCH_RX_C_DN<2>")
	)
	(arc
		(start 360.237532 -217.388694)
		(mid 360.372465 -217.25534)
		(end 360.42473 -217.072972)
		(width 0.0889)
		(layer "In6.Cu")
		(net "DMI_CPU0_PCH_RX_C_DN<2>")
	)
	(arc
		(start 356.957122 -219.825316)
		(mid 357.088036 -219.688956)
		(end 357.135684 -219.506038)
		(width 0.0889)
		(layer "In6.Cu")
		(net "DMI_CPU0_PCH_RX_C_DN<2>")
	)
	(arc
		(start 356.66553 -220.319854)
		(mid 356.739521 -220.040288)
		(end 356.942136 -219.833952)
		(width 0.0889)
		(layer "In6.Cu")
		(net "DMI_CPU0_PCH_RX_C_DN<2>")
	)
	(arc
		(start 355.72573 -223.568006)
		(mid 355.803359 -223.289593)
		(end 356.008432 -223.085914)
		(width 0.0889)
		(layer "In6.Cu")
		(net "DMI_CPU0_PCH_RX_C_DN<2>")
	)
	(arc
		(start 361.646978 -214.947246)
		(mid 361.687648 -214.920052)
		(end 361.724448 -214.88781)
		(width 0.0889)
		(layer "In6.Cu")
		(net "DMI_CPU0_PCH_RX_C_DN<2>")
	)
	(arc
		(start 359.297732 -217.388694)
		(mid 359.580434 -217.312952)
		(end 359.863136 -217.388694)
		(width 0.0889)
		(layer "In6.Cu")
		(net "DMI_CPU0_PCH_RX_C_DN<2>")
	)
	(arc
		(start 357.417878 -217.388694)
		(mid 357.694691 -217.312858)
		(end 357.973122 -217.382598)
		(width 0.0889)
		(layer "In6.Cu")
		(net "DMI_CPU0_PCH_RX_C_DN<2>")
	)
	(arc
		(start 358.265984 -217.878406)
		(mid 358.313663 -218.061306)
		(end 358.444546 -218.197684)
		(width 0.0889)
		(layer "In6.Cu")
		(net "DMI_CPU0_PCH_RX_C_DN<2>")
	)
	(arc
		(start 355.256084 -225.99523)
		(mid 355.336995 -225.725102)
		(end 355.538278 -225.527616)
		(width 0.0889)
		(layer "In6.Cu")
		(net "DMI_CPU0_PCH_RX_C_DN<2>")
	)
	(arc
		(start 356.957122 -221.453202)
		(mid 357.13584 -221.133924)
		(end 356.957122 -220.814646)
		(width 0.0889)
		(layer "In6.Cu")
		(net "DMI_CPU0_PCH_RX_C_DN<2>")
	)
	(arc
		(start 356.017322 -223.080834)
		(mid 356.148236 -222.944474)
		(end 356.195884 -222.761556)
		(width 0.0889)
		(layer "In6.Cu")
		(net "DMI_CPU0_PCH_RX_C_DN<2>")
	)
	(arc
		(start 357.417878 -218.367864)
		(mid 357.215055 -218.167633)
		(end 357.135684 -217.8939)
		(width 0.0889)
		(layer "In6.Cu")
		(net "DMI_CPU0_PCH_RX_C_DN<2>")
	)
	(arc
		(start 357.135684 -219.490544)
		(mid 357.215054 -219.21681)
		(end 357.417878 -219.01658)
		(width 0.0889)
		(layer "In6.Cu")
		(net "DMI_CPU0_PCH_RX_C_DN<2>")
	)
	(arc
		(start 358.453436 -218.202764)
		(mid 358.640634 -218.252907)
		(end 358.827832 -218.202764)
		(width 0.0889)
		(layer "In6.Cu")
		(net "DMI_CPU0_PCH_RX_C_DN<2>")
	)
	(arc
		(start 356.948232 -220.809566)
		(mid 356.744751 -220.608762)
		(end 356.66553 -220.334078)
		(width 0.0889)
		(layer "In6.Cu")
		(net "DMI_CPU0_PCH_RX_C_DN<2>")
	)
	(arc
		(start 354.598732 -227.155502)
		(mid 354.733665 -227.022148)
		(end 354.78593 -226.83978)
		(width 0.0889)
		(layer "In6.Cu")
		(net "DMI_CPU0_PCH_RX_C_DN<2>")
	)
	(arc
		(start 357.983536 -217.388694)
		(mid 358.185822 -217.587675)
		(end 358.265984 -217.859864)
		(width 0.0889)
		(layer "In6.Cu")
		(net "DMI_CPU0_PCH_RX_C_DN<2>")
	)
	(arc
		(start 360.716068 -216.569798)
		(mid 360.846982 -216.433438)
		(end 360.89463 -216.25052)
		(width 0.0889)
		(layer "In6.Cu")
		(net "DMI_CPU0_PCH_RX_C_DN<2>")
	)
	(arc
		(start 356.195884 -222.746062)
		(mid 356.275254 -222.472328)
		(end 356.478078 -222.272098)
		(width 0.0889)
		(layer "In6.Cu")
		(net "DMI_CPU0_PCH_RX_C_DN<2>")
	)
	(arc
		(start 355.256084 -224.373948)
		(mid 355.335454 -224.100214)
		(end 355.538278 -223.899984)
		(width 0.0889)
		(layer "In6.Cu")
		(net "DMI_CPU0_PCH_RX_C_DN<2>")
	)
	(arc
		(start 355.538278 -224.8789)
		(mid 355.335455 -224.678669)
		(end 355.256084 -224.404936)
		(width 0.0889)
		(layer "In6.Cu")
		(net "DMI_CPU0_PCH_RX_C_DN<2>")
	)
	(arc
		(start 357.135684 -217.856308)
		(mid 357.216595 -217.58618)
		(end 357.417878 -217.388694)
		(width 0.0889)
		(layer "In6.Cu")
		(net "DMI_CPU0_PCH_RX_C_DN<2>")
	)
	(arc
		(start 361.185968 -215.755982)
		(mid 361.316882 -215.619622)
		(end 361.36453 -215.436704)
		(width 0.0889)
		(layer "In6.Cu")
		(net "DMI_CPU0_PCH_RX_C_DN<2>")
	)
	(arc
		(start 355.547168 -223.894904)
		(mid 355.678082 -223.758544)
		(end 355.72573 -223.575626)
		(width 0.0889)
		(layer "In6.Cu")
		(net "DMI_CPU0_PCH_RX_C_DN<2>")
	)
	(arc
		(start 355.72573 -225.203258)
		(mid 355.678051 -225.020358)
		(end 355.547168 -224.88398)
		(width 0.0889)
		(layer "In6.Cu")
		(net "DMI_CPU0_PCH_RX_C_DN<2>")
	)
	(arc
		(start 361.36453 -215.426798)
		(mid 361.442641 -215.149849)
		(end 361.646978 -214.947246)
		(width 0.0889)
		(layer "In6.Cu")
		(net "DMI_CPU0_PCH_RX_C_DN<2>")
	)
	(arc
		(start 356.486968 -222.267018)
		(mid 356.617882 -222.130658)
		(end 356.66553 -221.94774)
		(width 0.0889)
		(layer "In6.Cu")
		(net "DMI_CPU0_PCH_RX_C_DN<2>")
	)
	(arc
		(start 354.17633 -227.936806)
		(mid 354.279475 -227.806781)
		(end 354.316284 -227.64496)
		(width 0.0889)
		(layer "In6.Cu")
		(net "DMI_CPU0_PCH_RX_C_DN<2>")
	)
	(arc
		(start 355.725476 -225.21799)
		(mid 355.725673 -225.210625)
		(end 355.72573 -225.203258)
		(width 0.0889)
		(layer "In6.Cu")
		(net "DMI_CPU0_PCH_RX_C_DN<2>")
	)
	(arc
		(start 360.89463 -216.240614)
		(mid 360.972741 -215.963665)
		(end 361.177078 -215.761062)
		(width 0.0889)
		(layer "In6.Cu")
		(net "DMI_CPU0_PCH_RX_C_DN<2>")
	)
	(arc
		(start 360.42473 -217.05443)
		(mid 360.502841 -216.777481)
		(end 360.707178 -216.574878)
		(width 0.0889)
		(layer "In6.Cu")
		(net "DMI_CPU0_PCH_RX_C_DN<2>")
	)
	(arc
		(start 355.077522 -226.336606)
		(mid 355.208436 -226.200246)
		(end 355.256084 -226.017328)
		(width 0.0889)
		(layer "In6.Cu")
		(net "DMI_CPU0_PCH_RX_C_DN<2>")
	)
	(segment
		(start 353.00158 -228.1809)
		(end 353.001834 -228.180646)
		(width 0.13208)
		(layer "F.Cu")
		(net "DMI_CPU0_PCH_RX_C_DN<1>")
	)
	(segment
		(start 353.001834 -228.180646)
		(end 353.001834 -227.64496)
		(width 0.13208)
		(layer "F.Cu")
		(net "DMI_CPU0_PCH_RX_C_DN<1>")
	)
	(segment
		(start 340.0298 -67.019424)
		(end 340.35746 -66.691764)
		(width 0.13208)
		(layer "B.Cu")
		(net "DMI_CPU0_PCH_RX_C_DN<1>")
	)
	(segment
		(start 335.182972 -80.790542)
		(end 334.880712 -80.488282)
		(width 0.13208)
		(layer "B.Cu")
		(net "DMI_CPU0_PCH_RX_C_DN<1>")
	)
	(segment
		(start 334.880712 -80.488282)
		(end 334.880712 -79.724504)
		(width 0.13208)
		(layer "B.Cu")
		(net "DMI_CPU0_PCH_RX_C_DN<1>")
	)
	(segment
		(start 338.550504 -73.561448)
		(end 339.383116 -71.551038)
		(width 0.13208)
		(layer "B.Cu")
		(net "DMI_CPU0_PCH_RX_C_DN<1>")
	)
	(segment
		(start 340.0298 -67.81419)
		(end 340.0298 -67.019424)
		(width 0.13208)
		(layer "B.Cu")
		(net "DMI_CPU0_PCH_RX_C_DN<1>")
	)
	(segment
		(start 339.383116 -71.551038)
		(end 339.383116 -69.375528)
		(width 0.13208)
		(layer "B.Cu")
		(net "DMI_CPU0_PCH_RX_C_DN<1>")
	)
	(segment
		(start 338.520532 -76.084684)
		(end 338.520532 -73.7108)
		(width 0.13208)
		(layer "B.Cu")
		(net "DMI_CPU0_PCH_RX_C_DN<1>")
	)
	(segment
		(start 338.520532 -73.7108)
		(end 338.550504 -73.561448)
		(width 0.13208)
		(layer "B.Cu")
		(net "DMI_CPU0_PCH_RX_C_DN<1>")
	)
	(segment
		(start 339.383116 -69.375528)
		(end 340.0298 -67.81419)
		(width 0.13208)
		(layer "B.Cu")
		(net "DMI_CPU0_PCH_RX_C_DN<1>")
	)
	(segment
		(start 334.880712 -79.724504)
		(end 338.520532 -76.084684)
		(width 0.13208)
		(layer "B.Cu")
		(net "DMI_CPU0_PCH_RX_C_DN<1>")
	)
	(segment
		(start 354.685346 -224.70872)
		(end 354.694236 -224.7138)
		(width 0.0889)
		(layer "In6.Cu")
		(net "DMI_CPU0_PCH_RX_C_DN<1>")
	)
	(segment
		(start 354.694236 -224.065084)
		(end 354.685346 -224.070164)
		(width 0.0889)
		(layer "In6.Cu")
		(net "DMI_CPU0_PCH_RX_C_DN<1>")
	)
	(segment
		(start 356.564946 -218.197684)
		(end 356.573836 -218.202764)
		(width 0.0889)
		(layer "In6.Cu")
		(net "DMI_CPU0_PCH_RX_C_DN<1>")
	)
	(segment
		(start 372.668038 -192.709546)
		(end 367.821718 -196.102986)
		(width 0.14732)
		(layer "In6.Cu")
		(net "DMI_CPU0_PCH_RX_C_DN<1>")
	)
	(segment
		(start 356.856284 -217.0557)
		(end 356.856284 -217.082878)
		(width 0.0889)
		(layer "In6.Cu")
		(net "DMI_CPU0_PCH_RX_C_DN<1>")
	)
	(segment
		(start 334.888332 -81.085182)
		(end 334.888332 -83.747864)
		(width 0.14732)
		(layer "In6.Cu")
		(net "DMI_CPU0_PCH_RX_C_DN<1>")
	)
	(segment
		(start 356.573836 -217.554048)
		(end 356.564946 -217.559128)
		(width 0.0889)
		(layer "In6.Cu")
		(net "DMI_CPU0_PCH_RX_C_DN<1>")
	)
	(segment
		(start 356.100634 -219.997528)
		(end 356.095046 -220.000576)
		(width 0.0889)
		(layer "In6.Cu")
		(net "DMI_CPU0_PCH_RX_C_DN<1>")
	)
	(segment
		(start 360.760518 -215.140032)
		(end 360.760772 -215.140286)
		(width 0.0889)
		(layer "In6.Cu")
		(net "DMI_CPU0_PCH_RX_C_DN<1>")
	)
	(segment
		(start 354.221796 -226.50831)
		(end 354.221034 -226.508818)
		(width 0.0889)
		(layer "In6.Cu")
		(net "DMI_CPU0_PCH_RX_C_DN<1>")
	)
	(segment
		(start 355.634036 -222.437198)
		(end 355.625146 -222.442278)
		(width 0.0889)
		(layer "In6.Cu")
		(net "DMI_CPU0_PCH_RX_C_DN<1>")
	)
	(segment
		(start 355.91623 -221.94774)
		(end 355.91623 -221.963234)
		(width 0.0889)
		(layer "In6.Cu")
		(net "DMI_CPU0_PCH_RX_C_DN<1>")
	)
	(segment
		(start 356.101396 -219.99702)
		(end 356.100634 -219.997528)
		(width 0.0889)
		(layer "In6.Cu")
		(net "DMI_CPU0_PCH_RX_C_DN<1>")
	)
	(segment
		(start 354.97643 -225.187764)
		(end 354.97643 -225.225356)
		(width 0.0889)
		(layer "In6.Cu")
		(net "DMI_CPU0_PCH_RX_C_DN<1>")
	)
	(segment
		(start 361.336844 -212.085936)
		(end 361.294934 -212.127846)
		(width 0.0889)
		(layer "In6.Cu")
		(net "DMI_CPU0_PCH_RX_C_DN<1>")
	)
	(segment
		(start 356.386384 -219.506038)
		(end 356.386384 -219.515944)
		(width 0.0889)
		(layer "In6.Cu")
		(net "DMI_CPU0_PCH_RX_C_DN<1>")
	)
	(segment
		(start 376.99696 -186.526932)
		(end 372.668038 -192.709546)
		(width 0.14732)
		(layer "In6.Cu")
		(net "DMI_CPU0_PCH_RX_C_DN<1>")
	)
	(segment
		(start 361.192318 -214.721694)
		(end 360.872532 -215.041734)
		(width 0.0889)
		(layer "In6.Cu")
		(net "DMI_CPU0_PCH_RX_C_DN<1>")
	)
	(segment
		(start 356.386384 -221.115382)
		(end 356.386384 -221.133924)
		(width 0.0889)
		(layer "In6.Cu")
		(net "DMI_CPU0_PCH_RX_C_DN<1>")
	)
	(segment
		(start 361.336844 -209.348578)
		(end 361.336844 -212.063838)
		(width 0.14732)
		(layer "In6.Cu")
		(net "DMI_CPU0_PCH_RX_C_DN<1>")
	)
	(segment
		(start 355.446584 -222.761556)
		(end 355.446584 -222.77578)
		(width 0.0889)
		(layer "In6.Cu")
		(net "DMI_CPU0_PCH_RX_C_DN<1>")
	)
	(segment
		(start 361.336844 -212.063838)
		(end 361.336844 -212.085936)
		(width 0.0889)
		(layer "In6.Cu")
		(net "DMI_CPU0_PCH_RX_C_DN<1>")
	)
	(segment
		(start 353.760532 -227.317046)
		(end 353.754436 -227.320602)
		(width 0.0889)
		(layer "In6.Cu")
		(net "DMI_CPU0_PCH_RX_C_DN<1>")
	)
	(segment
		(start 354.694236 -225.69297)
		(end 354.685346 -225.69805)
		(width 0.0889)
		(layer "In6.Cu")
		(net "DMI_CPU0_PCH_RX_C_DN<1>")
	)
	(segment
		(start 354.223574 -226.507294)
		(end 354.221796 -226.50831)
		(width 0.0889)
		(layer "In6.Cu")
		(net "DMI_CPU0_PCH_RX_C_DN<1>")
	)
	(segment
		(start 356.85603 -218.676728)
		(end 356.85603 -218.707716)
		(width 0.0889)
		(layer "In6.Cu")
		(net "DMI_CPU0_PCH_RX_C_DN<1>")
	)
	(segment
		(start 356.102158 -221.624144)
		(end 356.094792 -221.628462)
		(width 0.0889)
		(layer "In6.Cu")
		(net "DMI_CPU0_PCH_RX_C_DN<1>")
	)
	(segment
		(start 360.145584 -216.241884)
		(end 360.145584 -216.260426)
		(width 0.0889)
		(layer "In6.Cu")
		(net "DMI_CPU0_PCH_RX_C_DN<1>")
	)
	(segment
		(start 356.103174 -219.996004)
		(end 356.101396 -219.99702)
		(width 0.0889)
		(layer "In6.Cu")
		(net "DMI_CPU0_PCH_RX_C_DN<1>")
	)
	(segment
		(start 335.182972 -80.790542)
		(end 334.888332 -81.085182)
		(width 0.14732)
		(layer "In6.Cu")
		(net "DMI_CPU0_PCH_RX_C_DN<1>")
	)
	(segment
		(start 337.01228 -91.534488)
		(end 375.46407 -156.779214)
		(width 0.14732)
		(layer "In6.Cu")
		(net "DMI_CPU0_PCH_RX_C_DN<1>")
	)
	(segment
		(start 356.573836 -219.18168)
		(end 356.564946 -219.18676)
		(width 0.0889)
		(layer "In6.Cu")
		(net "DMI_CPU0_PCH_RX_C_DN<1>")
	)
	(segment
		(start 357.983536 -216.739978)
		(end 357.973122 -216.746074)
		(width 0.0889)
		(layer "In6.Cu")
		(net "DMI_CPU0_PCH_RX_C_DN<1>")
	)
	(segment
		(start 361.294934 -212.127846)
		(end 361.294934 -214.47379)
		(width 0.0889)
		(layer "In6.Cu")
		(net "DMI_CPU0_PCH_RX_C_DN<1>")
	)
	(segment
		(start 360.61523 -215.436704)
		(end 360.61523 -215.44661)
		(width 0.0889)
		(layer "In6.Cu")
		(net "DMI_CPU0_PCH_RX_C_DN<1>")
	)
	(segment
		(start 375.46407 -156.779214)
		(end 378.855732 -175.996346)
		(width 0.14732)
		(layer "In6.Cu")
		(net "DMI_CPU0_PCH_RX_C_DN<1>")
	)
	(segment
		(start 353.158298 -227.373942)
		(end 353.001834 -227.64496)
		(width 0.0889)
		(layer "In6.Cu")
		(net "DMI_CPU0_PCH_RX_C_DN<1>")
	)
	(segment
		(start 367.821718 -196.102986)
		(end 362.27258 -204.027532)
		(width 0.14732)
		(layer "In6.Cu")
		(net "DMI_CPU0_PCH_RX_C_DN<1>")
	)
	(segment
		(start 362.27258 -204.027532)
		(end 361.336844 -209.348578)
		(width 0.14732)
		(layer "In6.Cu")
		(net "DMI_CPU0_PCH_RX_C_DN<1>")
	)
	(segment
		(start 356.095046 -220.639132)
		(end 356.103936 -220.644212)
		(width 0.0889)
		(layer "In6.Cu")
		(net "DMI_CPU0_PCH_RX_C_DN<1>")
	)
	(segment
		(start 356.104444 -221.622874)
		(end 356.103682 -221.623382)
		(width 0.0889)
		(layer "In6.Cu")
		(net "DMI_CPU0_PCH_RX_C_DN<1>")
	)
	(segment
		(start 353.247198 -227.35032)
		(end 353.158298 -227.373942)
		(width 0.0889)
		(layer "In6.Cu")
		(net "DMI_CPU0_PCH_RX_C_DN<1>")
	)
	(segment
		(start 356.109778 -221.619826)
		(end 356.104444 -221.622874)
		(width 0.0889)
		(layer "In6.Cu")
		(net "DMI_CPU0_PCH_RX_C_DN<1>")
	)
	(segment
		(start 334.888332 -83.747864)
		(end 337.01228 -91.534488)
		(width 0.14732)
		(layer "In6.Cu")
		(net "DMI_CPU0_PCH_RX_C_DN<1>")
	)
	(segment
		(start 354.224336 -226.506786)
		(end 354.223574 -226.507294)
		(width 0.0889)
		(layer "In6.Cu")
		(net "DMI_CPU0_PCH_RX_C_DN<1>")
	)
	(segment
		(start 356.103936 -219.995496)
		(end 356.103174 -219.996004)
		(width 0.0889)
		(layer "In6.Cu")
		(net "DMI_CPU0_PCH_RX_C_DN<1>")
	)
	(segment
		(start 354.506784 -226.017328)
		(end 354.506784 -226.027234)
		(width 0.0889)
		(layer "In6.Cu")
		(net "DMI_CPU0_PCH_RX_C_DN<1>")
	)
	(segment
		(start 354.976684 -223.56699)
		(end 354.976684 -223.585532)
		(width 0.0889)
		(layer "In6.Cu")
		(net "DMI_CPU0_PCH_RX_C_DN<1>")
	)
	(segment
		(start 378.855732 -175.996346)
		(end 376.99696 -186.526932)
		(width 0.14732)
		(layer "In6.Cu")
		(net "DMI_CPU0_PCH_RX_C_DN<1>")
	)
	(segment
		(start 354.221034 -226.508818)
		(end 354.215446 -226.511866)
		(width 0.0889)
		(layer "In6.Cu")
		(net "DMI_CPU0_PCH_RX_C_DN<1>")
	)
	(segment
		(start 356.103682 -221.623382)
		(end 356.102158 -221.624144)
		(width 0.0889)
		(layer "In6.Cu")
		(net "DMI_CPU0_PCH_RX_C_DN<1>")
	)
	(arc
		(start 354.685346 -224.070164)
		(mid 354.556057 -224.20365)
		(end 354.506784 -224.382838)
		(width 0.0889)
		(layer "In6.Cu")
		(net "DMI_CPU0_PCH_RX_C_DN<1>")
	)
	(arc
		(start 356.386638 -217.866214)
		(mid 356.386471 -217.87739)
		(end 356.386638 -217.888566)
		(width 0.0889)
		(layer "In6.Cu")
		(net "DMI_CPU0_PCH_RX_C_DN<1>")
	)
	(arc
		(start 360.332782 -215.926162)
		(mid 360.197849 -216.059516)
		(end 360.145584 -216.241884)
		(width 0.0889)
		(layer "In6.Cu")
		(net "DMI_CPU0_PCH_RX_C_DN<1>")
	)
	(arc
		(start 356.856284 -217.082878)
		(mid 356.776122 -217.355067)
		(end 356.573836 -217.554048)
		(width 0.0889)
		(layer "In6.Cu")
		(net "DMI_CPU0_PCH_RX_C_DN<1>")
	)
	(arc
		(start 356.103936 -220.644212)
		(mid 356.306222 -220.843193)
		(end 356.386384 -221.115382)
		(width 0.0889)
		(layer "In6.Cu")
		(net "DMI_CPU0_PCH_RX_C_DN<1>")
	)
	(arc
		(start 357.973122 -216.746074)
		(mid 357.69469 -216.81592)
		(end 357.417878 -216.739978)
		(width 0.0889)
		(layer "In6.Cu")
		(net "DMI_CPU0_PCH_RX_C_DN<1>")
	)
	(arc
		(start 354.506784 -224.399602)
		(mid 354.556875 -224.576797)
		(end 354.685346 -224.70872)
		(width 0.0889)
		(layer "In6.Cu")
		(net "DMI_CPU0_PCH_RX_C_DN<1>")
	)
	(arc
		(start 354.97643 -225.225356)
		(mid 354.895519 -225.495484)
		(end 354.694236 -225.69297)
		(width 0.0889)
		(layer "In6.Cu")
		(net "DMI_CPU0_PCH_RX_C_DN<1>")
	)
	(arc
		(start 356.85603 -218.707716)
		(mid 356.77666 -218.98145)
		(end 356.573836 -219.18168)
		(width 0.0889)
		(layer "In6.Cu")
		(net "DMI_CPU0_PCH_RX_C_DN<1>")
	)
	(arc
		(start 358.357932 -216.739978)
		(mid 358.170734 -216.689835)
		(end 357.983536 -216.739978)
		(width 0.0889)
		(layer "In6.Cu")
		(net "DMI_CPU0_PCH_RX_C_DN<1>")
	)
	(arc
		(start 360.61523 -215.44661)
		(mid 360.537119 -215.723559)
		(end 360.332782 -215.926162)
		(width 0.0889)
		(layer "In6.Cu")
		(net "DMI_CPU0_PCH_RX_C_DN<1>")
	)
	(arc
		(start 356.564946 -219.18676)
		(mid 356.434032 -219.32312)
		(end 356.386384 -219.506038)
		(width 0.0889)
		(layer "In6.Cu")
		(net "DMI_CPU0_PCH_RX_C_DN<1>")
	)
	(arc
		(start 356.564946 -217.559128)
		(mid 356.437135 -217.690221)
		(end 356.386638 -217.866214)
		(width 0.0889)
		(layer "In6.Cu")
		(net "DMI_CPU0_PCH_RX_C_DN<1>")
	)
	(arc
		(start 353.26701 -227.358448)
		(mid 353.257066 -227.354477)
		(end 353.247198 -227.35032)
		(width 0.0889)
		(layer "In6.Cu")
		(net "DMI_CPU0_PCH_RX_C_DN<1>")
	)
	(arc
		(start 359.863136 -216.739978)
		(mid 359.580434 -216.815754)
		(end 359.297732 -216.739978)
		(width 0.0889)
		(layer "In6.Cu")
		(net "DMI_CPU0_PCH_RX_C_DN<1>")
	)
	(arc
		(start 354.215446 -226.511866)
		(mid 354.084532 -226.648226)
		(end 354.036884 -226.831144)
		(width 0.0889)
		(layer "In6.Cu")
		(net "DMI_CPU0_PCH_RX_C_DN<1>")
	)
	(arc
		(start 357.417878 -216.739978)
		(mid 357.23068 -216.689835)
		(end 357.043482 -216.739978)
		(width 0.0889)
		(layer "In6.Cu")
		(net "DMI_CPU0_PCH_RX_C_DN<1>")
	)
	(arc
		(start 354.506784 -226.027234)
		(mid 354.428673 -226.304183)
		(end 354.224336 -226.506786)
		(width 0.0889)
		(layer "In6.Cu")
		(net "DMI_CPU0_PCH_RX_C_DN<1>")
	)
	(arc
		(start 355.91623 -221.963234)
		(mid 355.83686 -222.236968)
		(end 355.634036 -222.437198)
		(width 0.0889)
		(layer "In6.Cu")
		(net "DMI_CPU0_PCH_RX_C_DN<1>")
	)
	(arc
		(start 360.760772 -215.140286)
		(mid 360.653586 -215.271596)
		(end 360.61523 -215.436704)
		(width 0.0889)
		(layer "In6.Cu")
		(net "DMI_CPU0_PCH_RX_C_DN<1>")
	)
	(arc
		(start 355.446584 -222.77578)
		(mid 355.367365 -223.050465)
		(end 355.163882 -223.251268)
		(width 0.0889)
		(layer "In6.Cu")
		(net "DMI_CPU0_PCH_RX_C_DN<1>")
	)
	(arc
		(start 361.294934 -214.47379)
		(mid 361.268282 -214.607957)
		(end 361.192318 -214.721694)
		(width 0.0889)
		(layer "In6.Cu")
		(net "DMI_CPU0_PCH_RX_C_DN<1>")
	)
	(arc
		(start 356.386638 -217.888566)
		(mid 356.436653 -218.065697)
		(end 356.564946 -218.197684)
		(width 0.0889)
		(layer "In6.Cu")
		(net "DMI_CPU0_PCH_RX_C_DN<1>")
	)
	(arc
		(start 355.163882 -223.251268)
		(mid 355.028949 -223.384622)
		(end 354.976684 -223.56699)
		(width 0.0889)
		(layer "In6.Cu")
		(net "DMI_CPU0_PCH_RX_C_DN<1>")
	)
	(arc
		(start 360.872532 -215.041734)
		(mid 360.818054 -215.092625)
		(end 360.760518 -215.140032)
		(width 0.0889)
		(layer "In6.Cu")
		(net "DMI_CPU0_PCH_RX_C_DN<1>")
	)
	(arc
		(start 354.694236 -224.7138)
		(mid 354.897059 -224.914031)
		(end 354.97643 -225.187764)
		(width 0.0889)
		(layer "In6.Cu")
		(net "DMI_CPU0_PCH_RX_C_DN<1>")
	)
	(arc
		(start 360.145584 -216.260426)
		(mid 360.067473 -216.537375)
		(end 359.863136 -216.739978)
		(width 0.0889)
		(layer "In6.Cu")
		(net "DMI_CPU0_PCH_RX_C_DN<1>")
	)
	(arc
		(start 359.297732 -216.739978)
		(mid 359.110534 -216.689835)
		(end 358.923336 -216.739978)
		(width 0.0889)
		(layer "In6.Cu")
		(net "DMI_CPU0_PCH_RX_C_DN<1>")
	)
	(arc
		(start 354.976684 -223.585532)
		(mid 354.898573 -223.862481)
		(end 354.694236 -224.065084)
		(width 0.0889)
		(layer "In6.Cu")
		(net "DMI_CPU0_PCH_RX_C_DN<1>")
	)
	(arc
		(start 355.625146 -222.442278)
		(mid 355.494232 -222.578638)
		(end 355.446584 -222.761556)
		(width 0.0889)
		(layer "In6.Cu")
		(net "DMI_CPU0_PCH_RX_C_DN<1>")
	)
	(arc
		(start 354.036884 -226.831144)
		(mid 353.962968 -227.110646)
		(end 353.760532 -227.317046)
		(width 0.0889)
		(layer "In6.Cu")
		(net "DMI_CPU0_PCH_RX_C_DN<1>")
	)
	(arc
		(start 358.923336 -216.739978)
		(mid 358.640634 -216.815754)
		(end 358.357932 -216.739978)
		(width 0.0889)
		(layer "In6.Cu")
		(net "DMI_CPU0_PCH_RX_C_DN<1>")
	)
	(arc
		(start 356.573836 -218.202764)
		(mid 356.776659 -218.402995)
		(end 356.85603 -218.676728)
		(width 0.0889)
		(layer "In6.Cu")
		(net "DMI_CPU0_PCH_RX_C_DN<1>")
	)
	(arc
		(start 354.506784 -224.382838)
		(mid 354.50669 -224.39122)
		(end 354.506784 -224.399602)
		(width 0.0889)
		(layer "In6.Cu")
		(net "DMI_CPU0_PCH_RX_C_DN<1>")
	)
	(arc
		(start 354.507038 -226.002596)
		(mid 354.506841 -226.009961)
		(end 354.506784 -226.017328)
		(width 0.0889)
		(layer "In6.Cu")
		(net "DMI_CPU0_PCH_RX_C_DN<1>")
	)
	(arc
		(start 356.386384 -219.515944)
		(mid 356.308273 -219.792893)
		(end 356.103936 -219.995496)
		(width 0.0889)
		(layer "In6.Cu")
		(net "DMI_CPU0_PCH_RX_C_DN<1>")
	)
	(arc
		(start 353.754436 -227.320602)
		(mid 353.515023 -227.394934)
		(end 353.26701 -227.358448)
		(width 0.0889)
		(layer "In6.Cu")
		(net "DMI_CPU0_PCH_RX_C_DN<1>")
	)
	(arc
		(start 356.386384 -221.133924)
		(mid 356.312393 -221.41349)
		(end 356.109778 -221.619826)
		(width 0.0889)
		(layer "In6.Cu")
		(net "DMI_CPU0_PCH_RX_C_DN<1>")
	)
	(arc
		(start 354.685346 -225.69805)
		(mid 354.558092 -225.828016)
		(end 354.507038 -226.002596)
		(width 0.0889)
		(layer "In6.Cu")
		(net "DMI_CPU0_PCH_RX_C_DN<1>")
	)
	(arc
		(start 356.094792 -221.628462)
		(mid 355.963878 -221.764822)
		(end 355.91623 -221.94774)
		(width 0.0889)
		(layer "In6.Cu")
		(net "DMI_CPU0_PCH_RX_C_DN<1>")
	)
	(arc
		(start 357.043482 -216.739978)
		(mid 356.908549 -216.873332)
		(end 356.856284 -217.0557)
		(width 0.0889)
		(layer "In6.Cu")
		(net "DMI_CPU0_PCH_RX_C_DN<1>")
	)
	(arc
		(start 356.095046 -220.000576)
		(mid 355.916449 -220.319854)
		(end 356.095046 -220.639132)
		(width 0.0889)
		(layer "In6.Cu")
		(net "DMI_CPU0_PCH_RX_C_DN<1>")
	)
	(segment
		(start 352.062034 -228.180646)
		(end 352.062034 -227.64496)
		(width 0.13208)
		(layer "F.Cu")
		(net "DMI_CPU0_PCH_RX_C_DN<0>")
	)
	(segment
		(start 352.06178 -228.1809)
		(end 352.062034 -228.180646)
		(width 0.13208)
		(layer "F.Cu")
		(net "DMI_CPU0_PCH_RX_C_DN<0>")
	)
	(segment
		(start 337.96478 -66.451734)
		(end 337.561682 -65.47866)
		(width 0.13208)
		(layer "B.Cu")
		(net "DMI_CPU0_PCH_RX_C_DN<0>")
	)
	(segment
		(start 332.452218 -79.274162)
		(end 335.157318 -72.7456)
		(width 0.13208)
		(layer "B.Cu")
		(net "DMI_CPU0_PCH_RX_C_DN<0>")
	)
	(segment
		(start 335.910428 -71.99249)
		(end 337.361784 -71.391272)
		(width 0.13208)
		(layer "B.Cu")
		(net "DMI_CPU0_PCH_RX_C_DN<0>")
	)
	(segment
		(start 335.157318 -72.7456)
		(end 335.910428 -71.99249)
		(width 0.13208)
		(layer "B.Cu")
		(net "DMI_CPU0_PCH_RX_C_DN<0>")
	)
	(segment
		(start 337.647534 -71.105522)
		(end 337.96478 -70.339712)
		(width 0.13208)
		(layer "B.Cu")
		(net "DMI_CPU0_PCH_RX_C_DN<0>")
	)
	(segment
		(start 332.452218 -81.738724)
		(end 332.452218 -79.274162)
		(width 0.13208)
		(layer "B.Cu")
		(net "DMI_CPU0_PCH_RX_C_DN<0>")
	)
	(segment
		(start 337.561682 -65.47866)
		(end 337.561682 -64.925448)
		(width 0.13208)
		(layer "B.Cu")
		(net "DMI_CPU0_PCH_RX_C_DN<0>")
	)
	(segment
		(start 337.561682 -64.925448)
		(end 337.218782 -64.582548)
		(width 0.13208)
		(layer "B.Cu")
		(net "DMI_CPU0_PCH_RX_C_DN<0>")
	)
	(segment
		(start 337.96478 -70.339712)
		(end 337.96478 -66.451734)
		(width 0.13208)
		(layer "B.Cu")
		(net "DMI_CPU0_PCH_RX_C_DN<0>")
	)
	(segment
		(start 337.361784 -71.391272)
		(end 337.647534 -71.105522)
		(width 0.13208)
		(layer "B.Cu")
		(net "DMI_CPU0_PCH_RX_C_DN<0>")
	)
	(segment
		(start 332.149958 -82.040984)
		(end 332.452218 -81.738724)
		(width 0.13208)
		(layer "B.Cu")
		(net "DMI_CPU0_PCH_RX_C_DN<0>")
	)
	(segment
		(start 360.042968 -213.908894)
		(end 360.142028 -213.809834)
		(width 0.0889)
		(layer "In6.Cu")
		(net "DMI_CPU0_PCH_RX_C_DN<0>")
	)
	(segment
		(start 352.062034 -227.64496)
		(end 352.218498 -227.915978)
		(width 0.0889)
		(layer "In6.Cu")
		(net "DMI_CPU0_PCH_RX_C_DN<0>")
	)
	(segment
		(start 354.598478 -222.272098)
		(end 354.607368 -222.267018)
		(width 0.0889)
		(layer "In6.Cu")
		(net "DMI_CPU0_PCH_RX_C_DN<0>")
	)
	(segment
		(start 360.099864 -212.633052)
		(end 360.099864 -212.610954)
		(width 0.0889)
		(layer "In6.Cu")
		(net "DMI_CPU0_PCH_RX_C_DN<0>")
	)
	(segment
		(start 353.376484 -224.404936)
		(end 353.376484 -224.373948)
		(width 0.0889)
		(layer "In6.Cu")
		(net "DMI_CPU0_PCH_RX_C_DN<0>")
	)
	(segment
		(start 353.84613 -223.575626)
		(end 353.84613 -223.568006)
		(width 0.0889)
		(layer "In6.Cu")
		(net "DMI_CPU0_PCH_RX_C_DN<0>")
	)
	(segment
		(start 355.068632 -221.458282)
		(end 355.070156 -221.45752)
		(width 0.0889)
		(layer "In6.Cu")
		(net "DMI_CPU0_PCH_RX_C_DN<0>")
	)
	(segment
		(start 353.197922 -226.336352)
		(end 353.197922 -226.336606)
		(width 0.0889)
		(layer "In6.Cu")
		(net "DMI_CPU0_PCH_RX_C_DN<0>")
	)
	(segment
		(start 355.256084 -219.506038)
		(end 355.256084 -219.490544)
		(width 0.0889)
		(layer "In6.Cu")
		(net "DMI_CPU0_PCH_RX_C_DN<0>")
	)
	(segment
		(start 360.142028 -212.675216)
		(end 360.099864 -212.633052)
		(width 0.0889)
		(layer "In6.Cu")
		(net "DMI_CPU0_PCH_RX_C_DN<0>")
	)
	(segment
		(start 355.547168 -218.372944)
		(end 355.538278 -218.367864)
		(width 0.0889)
		(layer "In6.Cu")
		(net "DMI_CPU0_PCH_RX_C_DN<0>")
	)
	(segment
		(start 360.042968 -213.446614)
		(end 360.042968 -213.182454)
		(width 0.0889)
		(layer "In6.Cu")
		(net "DMI_CPU0_PCH_RX_C_DN<0>")
	)
	(segment
		(start 357.96855 -215.752426)
		(end 357.983282 -215.761062)
		(width 0.0889)
		(layer "In6.Cu")
		(net "DMI_CPU0_PCH_RX_C_DN<0>")
	)
	(segment
		(start 353.667568 -224.88398)
		(end 353.658678 -224.8789)
		(width 0.0889)
		(layer "In6.Cu")
		(net "DMI_CPU0_PCH_RX_C_DN<0>")
	)
	(segment
		(start 357.02875 -215.752426)
		(end 357.043482 -215.761062)
		(width 0.0889)
		(layer "In6.Cu")
		(net "DMI_CPU0_PCH_RX_C_DN<0>")
	)
	(segment
		(start 355.077522 -219.825062)
		(end 355.077522 -219.825316)
		(width 0.0889)
		(layer "In6.Cu")
		(net "DMI_CPU0_PCH_RX_C_DN<0>")
	)
	(segment
		(start 375.79681 -186.287156)
		(end 377.60656 -176.035716)
		(width 0.14732)
		(layer "In6.Cu")
		(net "DMI_CPU0_PCH_RX_C_DN<0>")
	)
	(segment
		(start 353.376484 -226.017328)
		(end 353.376484 -225.99523)
		(width 0.0889)
		(layer "In6.Cu")
		(net "DMI_CPU0_PCH_RX_C_DN<0>")
	)
	(segment
		(start 366.933226 -195.214494)
		(end 366.932718 -195.213986)
		(width 0.14732)
		(layer "In6.Cu")
		(net "DMI_CPU0_PCH_RX_C_DN<0>")
	)
	(segment
		(start 359.48493 -215.436704)
		(end 359.48493 -215.42248)
		(width 0.0889)
		(layer "In6.Cu")
		(net "DMI_CPU0_PCH_RX_C_DN<0>")
	)
	(segment
		(start 377.60656 -176.035716)
		(end 374.360694 -157.645862)
		(width 0.14732)
		(layer "In6.Cu")
		(net "DMI_CPU0_PCH_RX_C_DN<0>")
	)
	(segment
		(start 356.195884 -216.25052)
		(end 356.195884 -216.235026)
		(width 0.0889)
		(layer "In6.Cu")
		(net "DMI_CPU0_PCH_RX_C_DN<0>")
	)
	(segment
		(start 360.142028 -214.591392)
		(end 360.142028 -214.272114)
		(width 0.0889)
		(layer "In6.Cu")
		(net "DMI_CPU0_PCH_RX_C_DN<0>")
	)
	(segment
		(start 355.256084 -217.8939)
		(end 355.256084 -217.856308)
		(width 0.0889)
		(layer "In6.Cu")
		(net "DMI_CPU0_PCH_RX_C_DN<0>")
	)
	(segment
		(start 360.099864 -212.610954)
		(end 360.099864 -209.239866)
		(width 0.14732)
		(layer "In6.Cu")
		(net "DMI_CPU0_PCH_RX_C_DN<0>")
	)
	(segment
		(start 355.077522 -220.814646)
		(end 355.068632 -220.809566)
		(width 0.0889)
		(layer "In6.Cu")
		(net "DMI_CPU0_PCH_RX_C_DN<0>")
	)
	(segment
		(start 355.538278 -219.01658)
		(end 355.547168 -219.0115)
		(width 0.0889)
		(layer "In6.Cu")
		(net "DMI_CPU0_PCH_RX_C_DN<0>")
	)
	(segment
		(start 355.99624 -216.58199)
		(end 356.008432 -216.574878)
		(width 0.0889)
		(layer "In6.Cu")
		(net "DMI_CPU0_PCH_RX_C_DN<0>")
	)
	(segment
		(start 354.128832 -223.085914)
		(end 354.137722 -223.080834)
		(width 0.0889)
		(layer "In6.Cu")
		(net "DMI_CPU0_PCH_RX_C_DN<0>")
	)
	(segment
		(start 374.360694 -157.645862)
		(end 334.575404 -91.66987)
		(width 0.14732)
		(layer "In6.Cu")
		(net "DMI_CPU0_PCH_RX_C_DN<0>")
	)
	(segment
		(start 352.90633 -226.83978)
		(end 352.90633 -226.831144)
		(width 0.0889)
		(layer "In6.Cu")
		(net "DMI_CPU0_PCH_RX_C_DN<0>")
	)
	(segment
		(start 332.444598 -82.335624)
		(end 332.149958 -82.040984)
		(width 0.14732)
		(layer "In6.Cu")
		(net "DMI_CPU0_PCH_RX_C_DN<0>")
	)
	(segment
		(start 360.042968 -214.173054)
		(end 360.042968 -213.908894)
		(width 0.0889)
		(layer "In6.Cu")
		(net "DMI_CPU0_PCH_RX_C_DN<0>")
	)
	(segment
		(start 355.062536 -219.833952)
		(end 355.077522 -219.825062)
		(width 0.0889)
		(layer "In6.Cu")
		(net "DMI_CPU0_PCH_RX_C_DN<0>")
	)
	(segment
		(start 355.070156 -221.45752)
		(end 355.077522 -221.453202)
		(width 0.0889)
		(layer "In6.Cu")
		(net "DMI_CPU0_PCH_RX_C_DN<0>")
	)
	(segment
		(start 356.008432 -216.574878)
		(end 356.017322 -216.569798)
		(width 0.0889)
		(layer "In6.Cu")
		(net "DMI_CPU0_PCH_RX_C_DN<0>")
	)
	(segment
		(start 352.218498 -227.915978)
		(end 352.29673 -227.936806)
		(width 0.0889)
		(layer "In6.Cu")
		(net "DMI_CPU0_PCH_RX_C_DN<0>")
	)
	(segment
		(start 355.062536 -221.461838)
		(end 355.06787 -221.45879)
		(width 0.0889)
		(layer "In6.Cu")
		(net "DMI_CPU0_PCH_RX_C_DN<0>")
	)
	(segment
		(start 355.538278 -217.388694)
		(end 355.547168 -217.383614)
		(width 0.0889)
		(layer "In6.Cu")
		(net "DMI_CPU0_PCH_RX_C_DN<0>")
	)
	(segment
		(start 353.658678 -225.527616)
		(end 353.667568 -225.522536)
		(width 0.0889)
		(layer "In6.Cu")
		(net "DMI_CPU0_PCH_RX_C_DN<0>")
	)
	(segment
		(start 372.0592 -191.625728)
		(end 375.79681 -186.287156)
		(width 0.14732)
		(layer "In6.Cu")
		(net "DMI_CPU0_PCH_RX_C_DN<0>")
	)
	(segment
		(start 361.101386 -203.542392)
		(end 366.933226 -195.214494)
		(width 0.14732)
		(layer "In6.Cu")
		(net "DMI_CPU0_PCH_RX_C_DN<0>")
	)
	(segment
		(start 334.575404 -91.66987)
		(end 332.444598 -84.009992)
		(width 0.14732)
		(layer "In6.Cu")
		(net "DMI_CPU0_PCH_RX_C_DN<0>")
	)
	(segment
		(start 359.84561 -214.88781)
		(end 360.142028 -214.591392)
		(width 0.0889)
		(layer "In6.Cu")
		(net "DMI_CPU0_PCH_RX_C_DN<0>")
	)
	(segment
		(start 353.659694 -223.899476)
		(end 353.667568 -223.894904)
		(width 0.0889)
		(layer "In6.Cu")
		(net "DMI_CPU0_PCH_RX_C_DN<0>")
	)
	(segment
		(start 358.90835 -215.752426)
		(end 358.923082 -215.761062)
		(width 0.0889)
		(layer "In6.Cu")
		(net "DMI_CPU0_PCH_RX_C_DN<0>")
	)
	(segment
		(start 360.142028 -213.809834)
		(end 360.142028 -213.545674)
		(width 0.0889)
		(layer "In6.Cu")
		(net "DMI_CPU0_PCH_RX_C_DN<0>")
	)
	(segment
		(start 366.932718 -195.213986)
		(end 372.0592 -191.625728)
		(width 0.14732)
		(layer "In6.Cu")
		(net "DMI_CPU0_PCH_RX_C_DN<0>")
	)
	(segment
		(start 353.658678 -223.899984)
		(end 353.659694 -223.899476)
		(width 0.0889)
		(layer "In6.Cu")
		(net "DMI_CPU0_PCH_RX_C_DN<0>")
	)
	(segment
		(start 353.182936 -226.345242)
		(end 353.197922 -226.336352)
		(width 0.0889)
		(layer "In6.Cu")
		(net "DMI_CPU0_PCH_RX_C_DN<0>")
	)
	(segment
		(start 360.042968 -213.182454)
		(end 360.142028 -213.083394)
		(width 0.0889)
		(layer "In6.Cu")
		(net "DMI_CPU0_PCH_RX_C_DN<0>")
	)
	(segment
		(start 352.436684 -227.64496)
		(end 352.436684 -227.635054)
		(width 0.0889)
		(layer "In6.Cu")
		(net "DMI_CPU0_PCH_RX_C_DN<0>")
	)
	(segment
		(start 360.142028 -213.083394)
		(end 360.142028 -212.675216)
		(width 0.0889)
		(layer "In6.Cu")
		(net "DMI_CPU0_PCH_RX_C_DN<0>")
	)
	(segment
		(start 355.06787 -221.45879)
		(end 355.068632 -221.458282)
		(width 0.0889)
		(layer "In6.Cu")
		(net "DMI_CPU0_PCH_RX_C_DN<0>")
	)
	(segment
		(start 332.444598 -84.009992)
		(end 332.444598 -82.335624)
		(width 0.14732)
		(layer "In6.Cu")
		(net "DMI_CPU0_PCH_RX_C_DN<0>")
	)
	(segment
		(start 360.099864 -209.239866)
		(end 361.101386 -203.542392)
		(width 0.14732)
		(layer "In6.Cu")
		(net "DMI_CPU0_PCH_RX_C_DN<0>")
	)
	(segment
		(start 360.142028 -213.545674)
		(end 360.042968 -213.446614)
		(width 0.0889)
		(layer "In6.Cu")
		(net "DMI_CPU0_PCH_RX_C_DN<0>")
	)
	(segment
		(start 359.297478 -215.761062)
		(end 359.306368 -215.755982)
		(width 0.0889)
		(layer "In6.Cu")
		(net "DMI_CPU0_PCH_RX_C_DN<0>")
	)
	(segment
		(start 360.142028 -214.272114)
		(end 360.042968 -214.173054)
		(width 0.0889)
		(layer "In6.Cu")
		(net "DMI_CPU0_PCH_RX_C_DN<0>")
	)
	(segment
		(start 354.78593 -220.334078)
		(end 354.78593 -220.319854)
		(width 0.0889)
		(layer "In6.Cu")
		(net "DMI_CPU0_PCH_RX_C_DN<0>")
	)
	(segment
		(start 354.316284 -222.761556)
		(end 354.316284 -222.746062)
		(width 0.0889)
		(layer "In6.Cu")
		(net "DMI_CPU0_PCH_RX_C_DN<0>")
	)
	(arc
		(start 359.48493 -215.42248)
		(mid 359.564149 -215.147795)
		(end 359.767632 -214.946992)
		(width 0.0889)
		(layer "In6.Cu")
		(net "DMI_CPU0_PCH_RX_C_DN<0>")
	)
	(arc
		(start 354.78593 -221.94774)
		(mid 354.859921 -221.668174)
		(end 355.062536 -221.461838)
		(width 0.0889)
		(layer "In6.Cu")
		(net "DMI_CPU0_PCH_RX_C_DN<0>")
	)
	(arc
		(start 354.316284 -222.746062)
		(mid 354.395654 -222.472328)
		(end 354.598478 -222.272098)
		(width 0.0889)
		(layer "In6.Cu")
		(net "DMI_CPU0_PCH_RX_C_DN<0>")
	)
	(arc
		(start 353.376484 -224.373948)
		(mid 353.455854 -224.100214)
		(end 353.658678 -223.899984)
		(width 0.0889)
		(layer "In6.Cu")
		(net "DMI_CPU0_PCH_RX_C_DN<0>")
	)
	(arc
		(start 356.478078 -215.761062)
		(mid 356.752277 -215.685227)
		(end 357.02875 -215.752426)
		(width 0.0889)
		(layer "In6.Cu")
		(net "DMI_CPU0_PCH_RX_C_DN<0>")
	)
	(arc
		(start 355.547168 -217.383614)
		(mid 355.678082 -217.247254)
		(end 355.72573 -217.064336)
		(width 0.0889)
		(layer "In6.Cu")
		(net "DMI_CPU0_PCH_RX_C_DN<0>")
	)
	(arc
		(start 353.376484 -225.99523)
		(mid 353.457395 -225.725102)
		(end 353.658678 -225.527616)
		(width 0.0889)
		(layer "In6.Cu")
		(net "DMI_CPU0_PCH_RX_C_DN<0>")
	)
	(arc
		(start 356.195884 -216.235026)
		(mid 356.275254 -215.961292)
		(end 356.478078 -215.761062)
		(width 0.0889)
		(layer "In6.Cu")
		(net "DMI_CPU0_PCH_RX_C_DN<0>")
	)
	(arc
		(start 355.547168 -219.0115)
		(mid 355.725644 -218.692222)
		(end 355.547168 -218.372944)
		(width 0.0889)
		(layer "In6.Cu")
		(net "DMI_CPU0_PCH_RX_C_DN<0>")
	)
	(arc
		(start 354.78593 -220.319854)
		(mid 354.859921 -220.040288)
		(end 355.062536 -219.833952)
		(width 0.0889)
		(layer "In6.Cu")
		(net "DMI_CPU0_PCH_RX_C_DN<0>")
	)
	(arc
		(start 357.417878 -215.761062)
		(mid 357.692077 -215.685227)
		(end 357.96855 -215.752426)
		(width 0.0889)
		(layer "In6.Cu")
		(net "DMI_CPU0_PCH_RX_C_DN<0>")
	)
	(arc
		(start 353.845876 -225.21799)
		(mid 353.846073 -225.210625)
		(end 353.84613 -225.203258)
		(width 0.0889)
		(layer "In6.Cu")
		(net "DMI_CPU0_PCH_RX_C_DN<0>")
	)
	(arc
		(start 359.767632 -214.946992)
		(mid 359.808562 -214.919959)
		(end 359.84561 -214.88781)
		(width 0.0889)
		(layer "In6.Cu")
		(net "DMI_CPU0_PCH_RX_C_DN<0>")
	)
	(arc
		(start 355.256084 -219.490544)
		(mid 355.335454 -219.21681)
		(end 355.538278 -219.01658)
		(width 0.0889)
		(layer "In6.Cu")
		(net "DMI_CPU0_PCH_RX_C_DN<0>")
	)
	(arc
		(start 352.436684 -227.635054)
		(mid 352.514795 -227.358105)
		(end 352.719132 -227.155502)
		(width 0.0889)
		(layer "In6.Cu")
		(net "DMI_CPU0_PCH_RX_C_DN<0>")
	)
	(arc
		(start 358.357678 -215.761062)
		(mid 358.631877 -215.685227)
		(end 358.90835 -215.752426)
		(width 0.0889)
		(layer "In6.Cu")
		(net "DMI_CPU0_PCH_RX_C_DN<0>")
	)
	(arc
		(start 353.84613 -223.568006)
		(mid 353.923759 -223.289593)
		(end 354.128832 -223.085914)
		(width 0.0889)
		(layer "In6.Cu")
		(net "DMI_CPU0_PCH_RX_C_DN<0>")
	)
	(arc
		(start 355.538278 -218.367864)
		(mid 355.335455 -218.167633)
		(end 355.256084 -217.8939)
		(width 0.0889)
		(layer "In6.Cu")
		(net "DMI_CPU0_PCH_RX_C_DN<0>")
	)
	(arc
		(start 355.077522 -219.825316)
		(mid 355.208436 -219.688956)
		(end 355.256084 -219.506038)
		(width 0.0889)
		(layer "In6.Cu")
		(net "DMI_CPU0_PCH_RX_C_DN<0>")
	)
	(arc
		(start 356.017322 -216.569798)
		(mid 356.148236 -216.433438)
		(end 356.195884 -216.25052)
		(width 0.0889)
		(layer "In6.Cu")
		(net "DMI_CPU0_PCH_RX_C_DN<0>")
	)
	(arc
		(start 353.667568 -225.522536)
		(mid 353.794822 -225.39257)
		(end 353.845876 -225.21799)
		(width 0.0889)
		(layer "In6.Cu")
		(net "DMI_CPU0_PCH_RX_C_DN<0>")
	)
	(arc
		(start 353.197922 -226.336606)
		(mid 353.328836 -226.200246)
		(end 353.376484 -226.017328)
		(width 0.0889)
		(layer "In6.Cu")
		(net "DMI_CPU0_PCH_RX_C_DN<0>")
	)
	(arc
		(start 354.607368 -222.267018)
		(mid 354.738282 -222.130658)
		(end 354.78593 -221.94774)
		(width 0.0889)
		(layer "In6.Cu")
		(net "DMI_CPU0_PCH_RX_C_DN<0>")
	)
	(arc
		(start 357.043482 -215.761062)
		(mid 357.23068 -215.811205)
		(end 357.417878 -215.761062)
		(width 0.0889)
		(layer "In6.Cu")
		(net "DMI_CPU0_PCH_RX_C_DN<0>")
	)
	(arc
		(start 353.84613 -225.203258)
		(mid 353.798451 -225.020358)
		(end 353.667568 -224.88398)
		(width 0.0889)
		(layer "In6.Cu")
		(net "DMI_CPU0_PCH_RX_C_DN<0>")
	)
	(arc
		(start 352.90633 -226.831144)
		(mid 352.980321 -226.551578)
		(end 353.182936 -226.345242)
		(width 0.0889)
		(layer "In6.Cu")
		(net "DMI_CPU0_PCH_RX_C_DN<0>")
	)
	(arc
		(start 358.923082 -215.761062)
		(mid 359.11028 -215.811205)
		(end 359.297478 -215.761062)
		(width 0.0889)
		(layer "In6.Cu")
		(net "DMI_CPU0_PCH_RX_C_DN<0>")
	)
	(arc
		(start 354.137722 -223.080834)
		(mid 354.268636 -222.944474)
		(end 354.316284 -222.761556)
		(width 0.0889)
		(layer "In6.Cu")
		(net "DMI_CPU0_PCH_RX_C_DN<0>")
	)
	(arc
		(start 355.068632 -220.809566)
		(mid 354.865151 -220.608762)
		(end 354.78593 -220.334078)
		(width 0.0889)
		(layer "In6.Cu")
		(net "DMI_CPU0_PCH_RX_C_DN<0>")
	)
	(arc
		(start 353.667568 -223.894904)
		(mid 353.798482 -223.758544)
		(end 353.84613 -223.575626)
		(width 0.0889)
		(layer "In6.Cu")
		(net "DMI_CPU0_PCH_RX_C_DN<0>")
	)
	(arc
		(start 352.29673 -227.936806)
		(mid 352.399875 -227.806781)
		(end 352.436684 -227.64496)
		(width 0.0889)
		(layer "In6.Cu")
		(net "DMI_CPU0_PCH_RX_C_DN<0>")
	)
	(arc
		(start 355.077522 -221.453202)
		(mid 355.25624 -221.133924)
		(end 355.077522 -220.814646)
		(width 0.0889)
		(layer "In6.Cu")
		(net "DMI_CPU0_PCH_RX_C_DN<0>")
	)
	(arc
		(start 355.72573 -217.064336)
		(mid 355.797965 -216.787812)
		(end 355.99624 -216.58199)
		(width 0.0889)
		(layer "In6.Cu")
		(net "DMI_CPU0_PCH_RX_C_DN<0>")
	)
	(arc
		(start 359.306368 -215.755982)
		(mid 359.437282 -215.619622)
		(end 359.48493 -215.436704)
		(width 0.0889)
		(layer "In6.Cu")
		(net "DMI_CPU0_PCH_RX_C_DN<0>")
	)
	(arc
		(start 355.256084 -217.856308)
		(mid 355.336995 -217.58618)
		(end 355.538278 -217.388694)
		(width 0.0889)
		(layer "In6.Cu")
		(net "DMI_CPU0_PCH_RX_C_DN<0>")
	)
	(arc
		(start 352.719132 -227.155502)
		(mid 352.854065 -227.022148)
		(end 352.90633 -226.83978)
		(width 0.0889)
		(layer "In6.Cu")
		(net "DMI_CPU0_PCH_RX_C_DN<0>")
	)
	(arc
		(start 357.983282 -215.761062)
		(mid 358.17048 -215.811205)
		(end 358.357678 -215.761062)
		(width 0.0889)
		(layer "In6.Cu")
		(net "DMI_CPU0_PCH_RX_C_DN<0>")
	)
	(arc
		(start 353.658678 -224.8789)
		(mid 353.455855 -224.678669)
		(end 353.376484 -224.404936)
		(width 0.0889)
		(layer "In6.Cu")
		(net "DMI_CPU0_PCH_RX_C_DN<0>")
	)
	(segment
		(start 352.3234 -8.362188)
		(end 352.476054 -8.255254)
		(width 0.13208)
		(layer "F.Cu")
		(net "DELTA_L_85_5INCH_TOP_DP")
	)
	(segment
		(start 353.538282 -2.231644)
		(end 353.866958 -2.001012)
		(width 0.13208)
		(layer "F.Cu")
		(net "DELTA_L_85_5INCH_TOP_DP")
	)
	(segment
		(start 377.16333 -4.44627)
		(end 377.274074 -4.44627)
		(width 0.13208)
		(layer "F.Cu")
		(net "DELTA_L_85_5INCH_TOP_DP")
	)
	(segment
		(start 364.29442 -2.224278)
		(end 364.623604 -1.994154)
		(width 0.13208)
		(layer "F.Cu")
		(net "DELTA_L_85_5INCH_TOP_DP")
	)
	(segment
		(start 358.263698 -8.155686)
		(end 359.496614 -8.37311)
		(width 0.13208)
		(layer "F.Cu")
		(net "DELTA_L_85_5INCH_TOP_DP")
	)
	(segment
		(start 358.160574 -8.00862)
		(end 358.263698 -8.155686)
		(width 0.13208)
		(layer "F.Cu")
		(net "DELTA_L_85_5INCH_TOP_DP")
	)
	(segment
		(start 362.71835 -2.490978)
		(end 361.740704 -8.03529)
		(width 0.13208)
		(layer "F.Cu")
		(net "DELTA_L_85_5INCH_TOP_DP")
	)
	(segment
		(start 351.713546 -2.270506)
		(end 351.944432 -2.599436)
		(width 0.13208)
		(layer "F.Cu")
		(net "DELTA_L_85_5INCH_TOP_DP")
	)
	(segment
		(start 368.203988 -2.021078)
		(end 369.63858 -2.273808)
		(width 0.13208)
		(layer "F.Cu")
		(net "DELTA_L_85_5INCH_TOP_DP")
	)
	(segment
		(start 346.36964 -2.22123)
		(end 346.698824 -1.991106)
		(width 0.13208)
		(layer "F.Cu")
		(net "DELTA_L_85_5INCH_TOP_DP")
	)
	(segment
		(start 340.124034 -4.44627)
		(end 340.240366 -4.44627)
		(width 0.13208)
		(layer "F.Cu")
		(net "DELTA_L_85_5INCH_TOP_DP")
	)
	(segment
		(start 355.91242 -8.36803)
		(end 356.059486 -8.264906)
		(width 0.13208)
		(layer "F.Cu")
		(net "DELTA_L_85_5INCH_TOP_DP")
	)
	(segment
		(start 352.476054 -8.255254)
		(end 353.538282 -2.231644)
		(width 0.13208)
		(layer "F.Cu")
		(net "DELTA_L_85_5INCH_TOP_DP")
	)
	(segment
		(start 363.076744 -8.39978)
		(end 363.22381 -8.296656)
		(width 0.13208)
		(layer "F.Cu")
		(net "DELTA_L_85_5INCH_TOP_DP")
	)
	(segment
		(start 359.116376 -2.588006)
		(end 358.160574 -8.00862)
		(width 0.13208)
		(layer "F.Cu")
		(net "DELTA_L_85_5INCH_TOP_DP")
	)
	(segment
		(start 354.679504 -8.150606)
		(end 355.91242 -8.36803)
		(width 0.13208)
		(layer "F.Cu")
		(net "DELTA_L_85_5INCH_TOP_DP")
	)
	(segment
		(start 368.91087 -8.036052)
		(end 369.013994 -8.183118)
		(width 0.13208)
		(layer "F.Cu")
		(net "DELTA_L_85_5INCH_TOP_DP")
	)
	(segment
		(start 349.950278 -2.2479)
		(end 350.278954 -2.017776)
		(width 0.13208)
		(layer "F.Cu")
		(net "DELTA_L_85_5INCH_TOP_DP")
	)
	(segment
		(start 345.33078 -8.112506)
		(end 346.36964 -2.22123)
		(width 0.13208)
		(layer "F.Cu")
		(net "DELTA_L_85_5INCH_TOP_DP")
	)
	(segment
		(start 366.676178 -8.317992)
		(end 366.823244 -8.214868)
		(width 0.13208)
		(layer "F.Cu")
		(net "DELTA_L_85_5INCH_TOP_DP")
	)
	(segment
		(start 340.240366 -4.44627)
		(end 340.360762 -4.566666)
		(width 0.13208)
		(layer "F.Cu")
		(net "DELTA_L_85_5INCH_TOP_DP")
	)
	(segment
		(start 370.247164 -8.400542)
		(end 370.39423 -8.297418)
		(width 0.13208)
		(layer "F.Cu")
		(net "DELTA_L_85_5INCH_TOP_DP")
	)
	(segment
		(start 365.443262 -8.100568)
		(end 366.676178 -8.317992)
		(width 0.13208)
		(layer "F.Cu")
		(net "DELTA_L_85_5INCH_TOP_DP")
	)
	(segment
		(start 357.451152 -2.005838)
		(end 358.886252 -2.258822)
		(width 0.13208)
		(layer "F.Cu")
		(net "DELTA_L_85_5INCH_TOP_DP")
	)
	(segment
		(start 355.532436 -2.582926)
		(end 354.57638 -8.00354)
		(width 0.13208)
		(layer "F.Cu")
		(net "DELTA_L_85_5INCH_TOP_DP")
	)
	(segment
		(start 377.042934 -4.566666)
		(end 377.16333 -4.44627)
		(width 0.13208)
		(layer "F.Cu")
		(net "DELTA_L_85_5INCH_TOP_DP")
	)
	(segment
		(start 348.895416 -8.228584)
		(end 349.950278 -2.2479)
		(width 0.13208)
		(layer "F.Cu")
		(net "DELTA_L_85_5INCH_TOP_DP")
	)
	(segment
		(start 347.412564 -7.966964)
		(end 347.519752 -8.119872)
		(width 0.13208)
		(layer "F.Cu")
		(net "DELTA_L_85_5INCH_TOP_DP")
	)
	(segment
		(start 351.100136 -8.146288)
		(end 352.3234 -8.362188)
		(width 0.13208)
		(layer "F.Cu")
		(net "DELTA_L_85_5INCH_TOP_DP")
	)
	(segment
		(start 355.301804 -2.253996)
		(end 355.532436 -2.582926)
		(width 0.13208)
		(layer "F.Cu")
		(net "DELTA_L_85_5INCH_TOP_DP")
	)
	(segment
		(start 371.577108 -4.566666)
		(end 377.042934 -4.566666)
		(width 0.13208)
		(layer "F.Cu")
		(net "DELTA_L_85_5INCH_TOP_DP")
	)
	(segment
		(start 369.868704 -2.602992)
		(end 368.91087 -8.036052)
		(width 0.13208)
		(layer "F.Cu")
		(net "DELTA_L_85_5INCH_TOP_DP")
	)
	(segment
		(start 361.843828 -8.182356)
		(end 363.076744 -8.39978)
		(width 0.13208)
		(layer "F.Cu")
		(net "DELTA_L_85_5INCH_TOP_DP")
	)
	(segment
		(start 354.57638 -8.00354)
		(end 354.679504 -8.150606)
		(width 0.13208)
		(layer "F.Cu")
		(net "DELTA_L_85_5INCH_TOP_DP")
	)
	(segment
		(start 360.72445 -2.139696)
		(end 361.053634 -1.909572)
		(width 0.13208)
		(layer "F.Cu")
		(net "DELTA_L_85_5INCH_TOP_DP")
	)
	(segment
		(start 353.866958 -2.001012)
		(end 355.301804 -2.253996)
		(width 0.13208)
		(layer "F.Cu")
		(net "DELTA_L_85_5INCH_TOP_DP")
	)
	(segment
		(start 367.875058 -2.251202)
		(end 368.203988 -2.021078)
		(width 0.13208)
		(layer "F.Cu")
		(net "DELTA_L_85_5INCH_TOP_DP")
	)
	(segment
		(start 351.944432 -2.599436)
		(end 350.992948 -7.993634)
		(width 0.13208)
		(layer "F.Cu")
		(net "DELTA_L_85_5INCH_TOP_DP")
	)
	(segment
		(start 346.698824 -1.991106)
		(end 348.133416 -2.243836)
		(width 0.13208)
		(layer "F.Cu")
		(net "DELTA_L_85_5INCH_TOP_DP")
	)
	(segment
		(start 357.122476 -2.23647)
		(end 357.451152 -2.005838)
		(width 0.13208)
		(layer "F.Cu")
		(net "DELTA_L_85_5INCH_TOP_DP")
	)
	(segment
		(start 364.623604 -1.994154)
		(end 366.058196 -2.247138)
		(width 0.13208)
		(layer "F.Cu")
		(net "DELTA_L_85_5INCH_TOP_DP")
	)
	(segment
		(start 344.312494 -5.216906)
		(end 343.845896 -7.85241)
		(width 0.13208)
		(layer "F.Cu")
		(net "DELTA_L_85_5INCH_TOP_DP")
	)
	(segment
		(start 361.053634 -1.909572)
		(end 362.48848 -2.162302)
		(width 0.13208)
		(layer "F.Cu")
		(net "DELTA_L_85_5INCH_TOP_DP")
	)
	(segment
		(start 365.340138 -7.953502)
		(end 365.443262 -8.100568)
		(width 0.13208)
		(layer "F.Cu")
		(net "DELTA_L_85_5INCH_TOP_DP")
	)
	(segment
		(start 369.63858 -2.273808)
		(end 369.868704 -2.602992)
		(width 0.13208)
		(layer "F.Cu")
		(net "DELTA_L_85_5INCH_TOP_DP")
	)
	(segment
		(start 340.360762 -4.566666)
		(end 343.661492 -4.566666)
		(width 0.13208)
		(layer "F.Cu")
		(net "DELTA_L_85_5INCH_TOP_DP")
	)
	(segment
		(start 350.278954 -2.017776)
		(end 351.713546 -2.270506)
		(width 0.13208)
		(layer "F.Cu")
		(net "DELTA_L_85_5INCH_TOP_DP")
	)
	(segment
		(start 366.288574 -2.576068)
		(end 365.340138 -7.953502)
		(width 0.13208)
		(layer "F.Cu")
		(net "DELTA_L_85_5INCH_TOP_DP")
	)
	(segment
		(start 366.058196 -2.247138)
		(end 366.288574 -2.576068)
		(width 0.13208)
		(layer "F.Cu")
		(net "DELTA_L_85_5INCH_TOP_DP")
	)
	(segment
		(start 359.496614 -8.37311)
		(end 359.64368 -8.269986)
		(width 0.13208)
		(layer "F.Cu")
		(net "DELTA_L_85_5INCH_TOP_DP")
	)
	(segment
		(start 366.823244 -8.214868)
		(end 367.875058 -2.251202)
		(width 0.13208)
		(layer "F.Cu")
		(net "DELTA_L_85_5INCH_TOP_DP")
	)
	(segment
		(start 370.39423 -8.297418)
		(end 370.939568 -5.204206)
		(width 0.13208)
		(layer "F.Cu")
		(net "DELTA_L_85_5INCH_TOP_DP")
	)
	(segment
		(start 356.059486 -8.264906)
		(end 357.122476 -2.23647)
		(width 0.13208)
		(layer "F.Cu")
		(net "DELTA_L_85_5INCH_TOP_DP")
	)
	(segment
		(start 362.48848 -2.162302)
		(end 362.71835 -2.490978)
		(width 0.13208)
		(layer "F.Cu")
		(net "DELTA_L_85_5INCH_TOP_DP")
	)
	(segment
		(start 347.519752 -8.119872)
		(end 348.743016 -8.335518)
		(width 0.13208)
		(layer "F.Cu")
		(net "DELTA_L_85_5INCH_TOP_DP")
	)
	(segment
		(start 370.939568 -5.204206)
		(end 371.577108 -4.566666)
		(width 0.13208)
		(layer "F.Cu")
		(net "DELTA_L_85_5INCH_TOP_DP")
	)
	(segment
		(start 348.36354 -2.57302)
		(end 347.412564 -7.966964)
		(width 0.13208)
		(layer "F.Cu")
		(net "DELTA_L_85_5INCH_TOP_DP")
	)
	(segment
		(start 343.661492 -4.566666)
		(end 344.312494 -5.216906)
		(width 0.13208)
		(layer "F.Cu")
		(net "DELTA_L_85_5INCH_TOP_DP")
	)
	(segment
		(start 358.886252 -2.258822)
		(end 359.116376 -2.588006)
		(width 0.13208)
		(layer "F.Cu")
		(net "DELTA_L_85_5INCH_TOP_DP")
	)
	(segment
		(start 348.743016 -8.335518)
		(end 348.895416 -8.228584)
		(width 0.13208)
		(layer "F.Cu")
		(net "DELTA_L_85_5INCH_TOP_DP")
	)
	(segment
		(start 350.992948 -7.993634)
		(end 351.100136 -8.146288)
		(width 0.13208)
		(layer "F.Cu")
		(net "DELTA_L_85_5INCH_TOP_DP")
	)
	(segment
		(start 343.95283 -8.005064)
		(end 345.176348 -8.220964)
		(width 0.13208)
		(layer "F.Cu")
		(net "DELTA_L_85_5INCH_TOP_DP")
	)
	(segment
		(start 359.64368 -8.269986)
		(end 360.72445 -2.139696)
		(width 0.13208)
		(layer "F.Cu")
		(net "DELTA_L_85_5INCH_TOP_DP")
	)
	(segment
		(start 369.013994 -8.183118)
		(end 370.247164 -8.400542)
		(width 0.13208)
		(layer "F.Cu")
		(net "DELTA_L_85_5INCH_TOP_DP")
	)
	(segment
		(start 348.133416 -2.243836)
		(end 348.36354 -2.57302)
		(width 0.13208)
		(layer "F.Cu")
		(net "DELTA_L_85_5INCH_TOP_DP")
	)
	(segment
		(start 343.845896 -7.85241)
		(end 343.95283 -8.005064)
		(width 0.13208)
		(layer "F.Cu")
		(net "DELTA_L_85_5INCH_TOP_DP")
	)
	(segment
		(start 361.740704 -8.03529)
		(end 361.843828 -8.182356)
		(width 0.13208)
		(layer "F.Cu")
		(net "DELTA_L_85_5INCH_TOP_DP")
	)
	(segment
		(start 345.176348 -8.220964)
		(end 345.33078 -8.112506)
		(width 0.13208)
		(layer "F.Cu")
		(net "DELTA_L_85_5INCH_TOP_DP")
	)
	(segment
		(start 363.22381 -8.296656)
		(end 364.29442 -2.224278)
		(width 0.13208)
		(layer "F.Cu")
		(net "DELTA_L_85_5INCH_TOP_DP")
	)
	(segment
		(start 346.75953 -2.264918)
		(end 347.98254 -2.480564)
		(width 0.13208)
		(layer "F.Cu")
		(net "DELTA_L_85_5INCH_TOP_DN")
	)
	(segment
		(start 347.98254 -2.480564)
		(end 348.089728 -2.633726)
		(width 0.13208)
		(layer "F.Cu")
		(net "DELTA_L_85_5INCH_TOP_DN")
	)
	(segment
		(start 370.630958 -8.44804)
		(end 371.180614 -5.329682)
		(width 0.13208)
		(layer "F.Cu")
		(net "DELTA_L_85_5INCH_TOP_DN")
	)
	(segment
		(start 347.138752 -8.02767)
		(end 347.368876 -8.3566)
		(width 0.13208)
		(layer "F.Cu")
		(net "DELTA_L_85_5INCH_TOP_DN")
	)
	(segment
		(start 340.124034 -4.946142)
		(end 340.234778 -4.946142)
		(width 0.13208)
		(layer "F.Cu")
		(net "DELTA_L_85_5INCH_TOP_DN")
	)
	(segment
		(start 356.296214 -8.415782)
		(end 357.359204 -2.387092)
		(width 0.13208)
		(layer "F.Cu")
		(net "DELTA_L_85_5INCH_TOP_DN")
	)
	(segment
		(start 368.969036 -8.438388)
		(end 370.308124 -8.674608)
		(width 0.13208)
		(layer "F.Cu")
		(net "DELTA_L_85_5INCH_TOP_DN")
	)
	(segment
		(start 359.880408 -8.420862)
		(end 360.961178 -2.290572)
		(width 0.13208)
		(layer "F.Cu")
		(net "DELTA_L_85_5INCH_TOP_DN")
	)
	(segment
		(start 350.719136 -8.05434)
		(end 350.94926 -8.383016)
		(width 0.13208)
		(layer "F.Cu")
		(net "DELTA_L_85_5INCH_TOP_DN")
	)
	(segment
		(start 351.562924 -2.507234)
		(end 351.670366 -2.660396)
		(width 0.13208)
		(layer "F.Cu")
		(net "DELTA_L_85_5INCH_TOP_DN")
	)
	(segment
		(start 370.308124 -8.674608)
		(end 370.630958 -8.44804)
		(width 0.13208)
		(layer "F.Cu")
		(net "DELTA_L_85_5INCH_TOP_DN")
	)
	(segment
		(start 365.90732 -2.483866)
		(end 366.014508 -2.636774)
		(width 0.13208)
		(layer "F.Cu")
		(net "DELTA_L_85_5INCH_TOP_DN")
	)
	(segment
		(start 368.264694 -2.29489)
		(end 369.487704 -2.510536)
		(width 0.13208)
		(layer "F.Cu")
		(net "DELTA_L_85_5INCH_TOP_DN")
	)
	(segment
		(start 348.089728 -2.633726)
		(end 347.138752 -8.02767)
		(width 0.13208)
		(layer "F.Cu")
		(net "DELTA_L_85_5INCH_TOP_DN")
	)
	(segment
		(start 353.927918 -2.275078)
		(end 355.151182 -2.490724)
		(width 0.13208)
		(layer "F.Cu")
		(net "DELTA_L_85_5INCH_TOP_DN")
	)
	(segment
		(start 368.969036 -8.438642)
		(end 368.969036 -8.438388)
		(width 0.13208)
		(layer "F.Cu")
		(net "DELTA_L_85_5INCH_TOP_DN")
	)
	(segment
		(start 343.801954 -8.241792)
		(end 345.237054 -8.494776)
		(width 0.13208)
		(layer "F.Cu")
		(net "DELTA_L_85_5INCH_TOP_DN")
	)
	(segment
		(start 357.359204 -2.387092)
		(end 357.512112 -2.279904)
		(width 0.13208)
		(layer "F.Cu")
		(net "DELTA_L_85_5INCH_TOP_DN")
	)
	(segment
		(start 344.033602 -5.30479)
		(end 343.57183 -7.913116)
		(width 0.13208)
		(layer "F.Cu")
		(net "DELTA_L_85_5INCH_TOP_DN")
	)
	(segment
		(start 352.712782 -8.405876)
		(end 353.77501 -2.382266)
		(width 0.13208)
		(layer "F.Cu")
		(net "DELTA_L_85_5INCH_TOP_DN")
	)
	(segment
		(start 345.237054 -8.494776)
		(end 345.567508 -8.263382)
		(width 0.13208)
		(layer "F.Cu")
		(net "DELTA_L_85_5INCH_TOP_DN")
	)
	(segment
		(start 363.13745 -8.673592)
		(end 363.460538 -8.447532)
		(width 0.13208)
		(layer "F.Cu")
		(net "DELTA_L_85_5INCH_TOP_DN")
	)
	(segment
		(start 352.384106 -8.636254)
		(end 352.712782 -8.405876)
		(width 0.13208)
		(layer "F.Cu")
		(net "DELTA_L_85_5INCH_TOP_DN")
	)
	(segment
		(start 350.94926 -8.383016)
		(end 352.384106 -8.636254)
		(width 0.13208)
		(layer "F.Cu")
		(net "DELTA_L_85_5INCH_TOP_DN")
	)
	(segment
		(start 357.512112 -2.279904)
		(end 358.735376 -2.49555)
		(width 0.13208)
		(layer "F.Cu")
		(net "DELTA_L_85_5INCH_TOP_DN")
	)
	(segment
		(start 362.444538 -2.551684)
		(end 361.466892 -8.095996)
		(width 0.13208)
		(layer "F.Cu")
		(net "DELTA_L_85_5INCH_TOP_DN")
	)
	(segment
		(start 366.736884 -8.591804)
		(end 367.059972 -8.365744)
		(width 0.13208)
		(layer "F.Cu")
		(net "DELTA_L_85_5INCH_TOP_DN")
	)
	(segment
		(start 348.803722 -8.609584)
		(end 349.132144 -8.37946)
		(width 0.13208)
		(layer "F.Cu")
		(net "DELTA_L_85_5INCH_TOP_DN")
	)
	(segment
		(start 346.606368 -2.372106)
		(end 346.75953 -2.264918)
		(width 0.13208)
		(layer "F.Cu")
		(net "DELTA_L_85_5INCH_TOP_DN")
	)
	(segment
		(start 371.180614 -5.329682)
		(end 371.68455 -4.825746)
		(width 0.13208)
		(layer "F.Cu")
		(net "DELTA_L_85_5INCH_TOP_DN")
	)
	(segment
		(start 369.594892 -2.663698)
		(end 368.637058 -8.096758)
		(width 0.13208)
		(layer "F.Cu")
		(net "DELTA_L_85_5INCH_TOP_DN")
	)
	(segment
		(start 371.68455 -4.825746)
		(end 377.037346 -4.825746)
		(width 0.13208)
		(layer "F.Cu")
		(net "DELTA_L_85_5INCH_TOP_DN")
	)
	(segment
		(start 347.368876 -8.3566)
		(end 348.803722 -8.609584)
		(width 0.13208)
		(layer "F.Cu")
		(net "DELTA_L_85_5INCH_TOP_DN")
	)
	(segment
		(start 361.466892 -8.095996)
		(end 361.692952 -8.419084)
		(width 0.13208)
		(layer "F.Cu")
		(net "DELTA_L_85_5INCH_TOP_DN")
	)
	(segment
		(start 377.157742 -4.946142)
		(end 377.274074 -4.946142)
		(width 0.13208)
		(layer "F.Cu")
		(net "DELTA_L_85_5INCH_TOP_DN")
	)
	(segment
		(start 368.111532 -2.402078)
		(end 368.264694 -2.29489)
		(width 0.13208)
		(layer "F.Cu")
		(net "DELTA_L_85_5INCH_TOP_DN")
	)
	(segment
		(start 350.33966 -2.291588)
		(end 351.562924 -2.507234)
		(width 0.13208)
		(layer "F.Cu")
		(net "DELTA_L_85_5INCH_TOP_DN")
	)
	(segment
		(start 340.355174 -4.825746)
		(end 343.55405 -4.825746)
		(width 0.13208)
		(layer "F.Cu")
		(net "DELTA_L_85_5INCH_TOP_DN")
	)
	(segment
		(start 362.337604 -2.39903)
		(end 362.444538 -2.551684)
		(width 0.13208)
		(layer "F.Cu")
		(net "DELTA_L_85_5INCH_TOP_DN")
	)
	(segment
		(start 358.842564 -2.648712)
		(end 357.886762 -8.069326)
		(width 0.13208)
		(layer "F.Cu")
		(net "DELTA_L_85_5INCH_TOP_DN")
	)
	(segment
		(start 354.302568 -8.064246)
		(end 354.528628 -8.387334)
		(width 0.13208)
		(layer "F.Cu")
		(net "DELTA_L_85_5INCH_TOP_DN")
	)
	(segment
		(start 350.187006 -2.398522)
		(end 350.33966 -2.291588)
		(width 0.13208)
		(layer "F.Cu")
		(net "DELTA_L_85_5INCH_TOP_DN")
	)
	(segment
		(start 361.692952 -8.419084)
		(end 363.13745 -8.673592)
		(width 0.13208)
		(layer "F.Cu")
		(net "DELTA_L_85_5INCH_TOP_DN")
	)
	(segment
		(start 343.55405 -4.825746)
		(end 344.033602 -5.30479)
		(width 0.13208)
		(layer "F.Cu")
		(net "DELTA_L_85_5INCH_TOP_DN")
	)
	(segment
		(start 355.973126 -8.641842)
		(end 356.296214 -8.415782)
		(width 0.13208)
		(layer "F.Cu")
		(net "DELTA_L_85_5INCH_TOP_DN")
	)
	(segment
		(start 343.57183 -7.913116)
		(end 343.801954 -8.241792)
		(width 0.13208)
		(layer "F.Cu")
		(net "DELTA_L_85_5INCH_TOP_DN")
	)
	(segment
		(start 365.066326 -8.014208)
		(end 365.292386 -8.337296)
		(width 0.13208)
		(layer "F.Cu")
		(net "DELTA_L_85_5INCH_TOP_DN")
	)
	(segment
		(start 345.567508 -8.263382)
		(end 346.606368 -2.372106)
		(width 0.13208)
		(layer "F.Cu")
		(net "DELTA_L_85_5INCH_TOP_DN")
	)
	(segment
		(start 360.961178 -2.290572)
		(end 361.11434 -2.183384)
		(width 0.13208)
		(layer "F.Cu")
		(net "DELTA_L_85_5INCH_TOP_DN")
	)
	(segment
		(start 354.528628 -8.387334)
		(end 355.973126 -8.641842)
		(width 0.13208)
		(layer "F.Cu")
		(net "DELTA_L_85_5INCH_TOP_DN")
	)
	(segment
		(start 361.11434 -2.183384)
		(end 362.337604 -2.39903)
		(width 0.13208)
		(layer "F.Cu")
		(net "DELTA_L_85_5INCH_TOP_DN")
	)
	(segment
		(start 364.68431 -2.267966)
		(end 365.90732 -2.483866)
		(width 0.13208)
		(layer "F.Cu")
		(net "DELTA_L_85_5INCH_TOP_DN")
	)
	(segment
		(start 368.637058 -8.096758)
		(end 368.863118 -8.419846)
		(width 0.13208)
		(layer "F.Cu")
		(net "DELTA_L_85_5INCH_TOP_DN")
	)
	(segment
		(start 358.112822 -8.392414)
		(end 359.55732 -8.646922)
		(width 0.13208)
		(layer "F.Cu")
		(net "DELTA_L_85_5INCH_TOP_DN")
	)
	(segment
		(start 353.77501 -2.382266)
		(end 353.927918 -2.275078)
		(width 0.13208)
		(layer "F.Cu")
		(net "DELTA_L_85_5INCH_TOP_DN")
	)
	(segment
		(start 368.863118 -8.419846)
		(end 368.969036 -8.438642)
		(width 0.13208)
		(layer "F.Cu")
		(net "DELTA_L_85_5INCH_TOP_DN")
	)
	(segment
		(start 367.059972 -8.365744)
		(end 368.111532 -2.402078)
		(width 0.13208)
		(layer "F.Cu")
		(net "DELTA_L_85_5INCH_TOP_DN")
	)
	(segment
		(start 340.234778 -4.946142)
		(end 340.355174 -4.825746)
		(width 0.13208)
		(layer "F.Cu")
		(net "DELTA_L_85_5INCH_TOP_DN")
	)
	(segment
		(start 355.25837 -2.643632)
		(end 354.302568 -8.064246)
		(width 0.13208)
		(layer "F.Cu")
		(net "DELTA_L_85_5INCH_TOP_DN")
	)
	(segment
		(start 351.670366 -2.660396)
		(end 350.719136 -8.05434)
		(width 0.13208)
		(layer "F.Cu")
		(net "DELTA_L_85_5INCH_TOP_DN")
	)
	(segment
		(start 369.487704 -2.510536)
		(end 369.594892 -2.663698)
		(width 0.13208)
		(layer "F.Cu")
		(net "DELTA_L_85_5INCH_TOP_DN")
	)
	(segment
		(start 349.132144 -8.37946)
		(end 350.187006 -2.398522)
		(width 0.13208)
		(layer "F.Cu")
		(net "DELTA_L_85_5INCH_TOP_DN")
	)
	(segment
		(start 357.886762 -8.069326)
		(end 358.112822 -8.392414)
		(width 0.13208)
		(layer "F.Cu")
		(net "DELTA_L_85_5INCH_TOP_DN")
	)
	(segment
		(start 359.55732 -8.646922)
		(end 359.880408 -8.420862)
		(width 0.13208)
		(layer "F.Cu")
		(net "DELTA_L_85_5INCH_TOP_DN")
	)
	(segment
		(start 355.151182 -2.490724)
		(end 355.25837 -2.643632)
		(width 0.13208)
		(layer "F.Cu")
		(net "DELTA_L_85_5INCH_TOP_DN")
	)
	(segment
		(start 366.014508 -2.636774)
		(end 365.066326 -8.014208)
		(width 0.13208)
		(layer "F.Cu")
		(net "DELTA_L_85_5INCH_TOP_DN")
	)
	(segment
		(start 363.460538 -8.447532)
		(end 364.531148 -2.375154)
		(width 0.13208)
		(layer "F.Cu")
		(net "DELTA_L_85_5INCH_TOP_DN")
	)
	(segment
		(start 365.292386 -8.337296)
		(end 366.736884 -8.591804)
		(width 0.13208)
		(layer "F.Cu")
		(net "DELTA_L_85_5INCH_TOP_DN")
	)
	(segment
		(start 377.037346 -4.825746)
		(end 377.157742 -4.946142)
		(width 0.13208)
		(layer "F.Cu")
		(net "DELTA_L_85_5INCH_TOP_DN")
	)
	(segment
		(start 358.735376 -2.49555)
		(end 358.842564 -2.648712)
		(width 0.13208)
		(layer "F.Cu")
		(net "DELTA_L_85_5INCH_TOP_DN")
	)
	(segment
		(start 364.531148 -2.375154)
		(end 364.68431 -2.267966)
		(width 0.13208)
		(layer "F.Cu")
		(net "DELTA_L_85_5INCH_TOP_DN")
	)
	(segment
		(start 249.82932 -2.408936)
		(end 249.148346 -2.5908)
		(width 0.13208)
		(layer "B.Cu")
		(net "DELTA_L_85_5INCH_IN4_DP")
	)
	(segment
		(start 212.67928 -2.408936)
		(end 213.360254 -2.5908)
		(width 0.13208)
		(layer "B.Cu")
		(net "DELTA_L_85_5INCH_IN4_DP")
	)
	(segment
		(start 227.319332 -5.967476)
		(end 227.569014 -6.3246)
		(width 0.14732)
		(layer "In11.Cu")
		(net "DELTA_L_85_5INCH_IN4_DP")
	)
	(segment
		(start 235.233718 -5.95884)
		(end 235.4834 -6.31571)
		(width 0.14732)
		(layer "In11.Cu")
		(net "DELTA_L_85_5INCH_IN4_DP")
	)
	(segment
		(start 223.609408 -6.342634)
		(end 225.191574 -6.62178)
		(width 0.14732)
		(layer "In11.Cu")
		(net "DELTA_L_85_5INCH_IN4_DP")
	)
	(segment
		(start 220.307154 -0.009652)
		(end 220.426788 -0.180594)
		(width 0.14732)
		(layer "In11.Cu")
		(net "DELTA_L_85_5INCH_IN4_DP")
	)
	(segment
		(start 229.507796 -6.354064)
		(end 230.65867 0.172466)
		(width 0.14732)
		(layer "In11.Cu")
		(net "DELTA_L_85_5INCH_IN4_DP")
	)
	(segment
		(start 217.59672 -2.29616)
		(end 218.515946 -1.376934)
		(width 0.14732)
		(layer "In11.Cu")
		(net "DELTA_L_85_5INCH_IN4_DP")
	)
	(segment
		(start 222.745046 0.168148)
		(end 222.91548 0.287782)
		(width 0.14732)
		(layer "In11.Cu")
		(net "DELTA_L_85_5INCH_IN4_DP")
	)
	(segment
		(start 229.151434 -6.603746)
		(end 229.507796 -6.354064)
		(width 0.14732)
		(layer "In11.Cu")
		(net "DELTA_L_85_5INCH_IN4_DP")
	)
	(segment
		(start 219.405454 -5.972048)
		(end 219.65539 -6.328664)
		(width 0.14732)
		(layer "In11.Cu")
		(net "DELTA_L_85_5INCH_IN4_DP")
	)
	(segment
		(start 228.346762 -0.140208)
		(end 227.319332 -5.967476)
		(width 0.14732)
		(layer "In11.Cu")
		(net "DELTA_L_85_5INCH_IN4_DP")
	)
	(segment
		(start 225.54819 -6.372098)
		(end 226.698302 0.150622)
		(width 0.14732)
		(layer "In11.Cu")
		(net "DELTA_L_85_5INCH_IN4_DP")
	)
	(segment
		(start 226.698302 0.150622)
		(end 226.86899 0.270002)
		(width 0.14732)
		(layer "In11.Cu")
		(net "DELTA_L_85_5INCH_IN4_DP")
	)
	(segment
		(start 240.094008 0.014478)
		(end 240.213388 -0.15621)
		(width 0.14732)
		(layer "In11.Cu")
		(net "DELTA_L_85_5INCH_IN4_DP")
	)
	(segment
		(start 235.4834 -6.31571)
		(end 237.06582 -6.594602)
		(width 0.14732)
		(layer "In11.Cu")
		(net "DELTA_L_85_5INCH_IN4_DP")
	)
	(segment
		(start 221.594172 -6.357874)
		(end 222.745046 0.168148)
		(width 0.14732)
		(layer "In11.Cu")
		(net "DELTA_L_85_5INCH_IN4_DP")
	)
	(segment
		(start 226.86899 0.270002)
		(end 228.227382 0.03048)
		(width 0.14732)
		(layer "In11.Cu")
		(net "DELTA_L_85_5INCH_IN4_DP")
	)
	(segment
		(start 245.97995 -2.690876)
		(end 246.374666 -2.29616)
		(width 0.14732)
		(layer "In11.Cu")
		(net "DELTA_L_85_5INCH_IN4_DP")
	)
	(segment
		(start 228.227382 0.03048)
		(end 228.346762 -0.140208)
		(width 0.14732)
		(layer "In11.Cu")
		(net "DELTA_L_85_5INCH_IN4_DP")
	)
	(segment
		(start 242.517676 0.113538)
		(end 242.688364 0.232918)
		(width 0.14732)
		(layer "In11.Cu")
		(net "DELTA_L_85_5INCH_IN4_DP")
	)
	(segment
		(start 238.735616 0.254)
		(end 240.094008 0.014478)
		(width 0.14732)
		(layer "In11.Cu")
		(net "DELTA_L_85_5INCH_IN4_DP")
	)
	(segment
		(start 244.97284 -6.627368)
		(end 245.32971 -6.377686)
		(width 0.14732)
		(layer "In11.Cu")
		(net "DELTA_L_85_5INCH_IN4_DP")
	)
	(segment
		(start 232.30713 -0.11811)
		(end 231.267762 -6.01218)
		(width 0.14732)
		(layer "In11.Cu")
		(net "DELTA_L_85_5INCH_IN4_DP")
	)
	(segment
		(start 213.360254 -2.5908)
		(end 213.654894 -2.29616)
		(width 0.14732)
		(layer "In11.Cu")
		(net "DELTA_L_85_5INCH_IN4_DP")
	)
	(segment
		(start 218.948762 0.22987)
		(end 220.307154 -0.009652)
		(width 0.14732)
		(layer "In11.Cu")
		(net "DELTA_L_85_5INCH_IN4_DP")
	)
	(segment
		(start 241.366548 -6.414516)
		(end 242.517676 0.113538)
		(width 0.14732)
		(layer "In11.Cu")
		(net "DELTA_L_85_5INCH_IN4_DP")
	)
	(segment
		(start 243.39042 -6.348222)
		(end 244.97284 -6.627368)
		(width 0.14732)
		(layer "In11.Cu")
		(net "DELTA_L_85_5INCH_IN4_DP")
	)
	(segment
		(start 231.517444 -6.368796)
		(end 233.099864 -6.647688)
		(width 0.14732)
		(layer "In11.Cu")
		(net "DELTA_L_85_5INCH_IN4_DP")
	)
	(segment
		(start 240.213388 -0.15621)
		(end 239.17783 -6.028436)
		(width 0.14732)
		(layer "In11.Cu")
		(net "DELTA_L_85_5INCH_IN4_DP")
	)
	(segment
		(start 239.427512 -6.385306)
		(end 241.009932 -6.664198)
		(width 0.14732)
		(layer "In11.Cu")
		(net "DELTA_L_85_5INCH_IN4_DP")
	)
	(segment
		(start 218.778328 0.110236)
		(end 218.948762 0.22987)
		(width 0.14732)
		(layer "In11.Cu")
		(net "DELTA_L_85_5INCH_IN4_DP")
	)
	(segment
		(start 233.099864 -6.647688)
		(end 233.45648 -6.398006)
		(width 0.14732)
		(layer "In11.Cu")
		(net "DELTA_L_85_5INCH_IN4_DP")
	)
	(segment
		(start 245.32971 -6.377686)
		(end 245.97995 -2.690876)
		(width 0.14732)
		(layer "In11.Cu")
		(net "DELTA_L_85_5INCH_IN4_DP")
	)
	(segment
		(start 227.569014 -6.3246)
		(end 229.151434 -6.603746)
		(width 0.14732)
		(layer "In11.Cu")
		(net "DELTA_L_85_5INCH_IN4_DP")
	)
	(segment
		(start 237.06582 -6.594602)
		(end 237.422182 -6.34492)
		(width 0.14732)
		(layer "In11.Cu")
		(net "DELTA_L_85_5INCH_IN4_DP")
	)
	(segment
		(start 241.009932 -6.664198)
		(end 241.366548 -6.414516)
		(width 0.14732)
		(layer "In11.Cu")
		(net "DELTA_L_85_5INCH_IN4_DP")
	)
	(segment
		(start 242.688364 0.232918)
		(end 244.046756 -0.006604)
		(width 0.14732)
		(layer "In11.Cu")
		(net "DELTA_L_85_5INCH_IN4_DP")
	)
	(segment
		(start 232.18775 0.052324)
		(end 232.30713 -0.11811)
		(width 0.14732)
		(layer "In11.Cu")
		(net "DELTA_L_85_5INCH_IN4_DP")
	)
	(segment
		(start 234.616752 0.182372)
		(end 234.78744 0.302006)
		(width 0.14732)
		(layer "In11.Cu")
		(net "DELTA_L_85_5INCH_IN4_DP")
	)
	(segment
		(start 213.654894 -2.29616)
		(end 217.59672 -2.29616)
		(width 0.14732)
		(layer "In11.Cu")
		(net "DELTA_L_85_5INCH_IN4_DP")
	)
	(segment
		(start 237.422182 -6.34492)
		(end 238.564928 0.134366)
		(width 0.14732)
		(layer "In11.Cu")
		(net "DELTA_L_85_5INCH_IN4_DP")
	)
	(segment
		(start 218.515946 -1.376934)
		(end 218.778328 0.110236)
		(width 0.14732)
		(layer "In11.Cu")
		(net "DELTA_L_85_5INCH_IN4_DP")
	)
	(segment
		(start 234.78744 0.302006)
		(end 236.145832 0.062484)
		(width 0.14732)
		(layer "In11.Cu")
		(net "DELTA_L_85_5INCH_IN4_DP")
	)
	(segment
		(start 243.140738 -5.991606)
		(end 243.39042 -6.348222)
		(width 0.14732)
		(layer "In11.Cu")
		(net "DELTA_L_85_5INCH_IN4_DP")
	)
	(segment
		(start 224.273872 0.04826)
		(end 224.393506 -0.122682)
		(width 0.14732)
		(layer "In11.Cu")
		(net "DELTA_L_85_5INCH_IN4_DP")
	)
	(segment
		(start 239.17783 -6.028436)
		(end 239.427512 -6.385306)
		(width 0.14732)
		(layer "In11.Cu")
		(net "DELTA_L_85_5INCH_IN4_DP")
	)
	(segment
		(start 233.45648 -6.398006)
		(end 234.616752 0.182372)
		(width 0.14732)
		(layer "In11.Cu")
		(net "DELTA_L_85_5INCH_IN4_DP")
	)
	(segment
		(start 231.267762 -6.01218)
		(end 231.517444 -6.368796)
		(width 0.14732)
		(layer "In11.Cu")
		(net "DELTA_L_85_5INCH_IN4_DP")
	)
	(segment
		(start 230.65867 0.172466)
		(end 230.829358 0.291846)
		(width 0.14732)
		(layer "In11.Cu")
		(net "DELTA_L_85_5INCH_IN4_DP")
	)
	(segment
		(start 244.166136 -0.177292)
		(end 243.140738 -5.991606)
		(width 0.14732)
		(layer "In11.Cu")
		(net "DELTA_L_85_5INCH_IN4_DP")
	)
	(segment
		(start 221.237556 -6.607556)
		(end 221.594172 -6.357874)
		(width 0.14732)
		(layer "In11.Cu")
		(net "DELTA_L_85_5INCH_IN4_DP")
	)
	(segment
		(start 220.426788 -0.180594)
		(end 219.405454 -5.972048)
		(width 0.14732)
		(layer "In11.Cu")
		(net "DELTA_L_85_5INCH_IN4_DP")
	)
	(segment
		(start 225.191574 -6.62178)
		(end 225.54819 -6.372098)
		(width 0.14732)
		(layer "In11.Cu")
		(net "DELTA_L_85_5INCH_IN4_DP")
	)
	(segment
		(start 222.91548 0.287782)
		(end 224.273872 0.04826)
		(width 0.14732)
		(layer "In11.Cu")
		(net "DELTA_L_85_5INCH_IN4_DP")
	)
	(segment
		(start 238.564928 0.134366)
		(end 238.735616 0.254)
		(width 0.14732)
		(layer "In11.Cu")
		(net "DELTA_L_85_5INCH_IN4_DP")
	)
	(segment
		(start 223.359472 -5.985764)
		(end 223.609408 -6.342634)
		(width 0.14732)
		(layer "In11.Cu")
		(net "DELTA_L_85_5INCH_IN4_DP")
	)
	(segment
		(start 230.829358 0.291846)
		(end 232.18775 0.052324)
		(width 0.14732)
		(layer "In11.Cu")
		(net "DELTA_L_85_5INCH_IN4_DP")
	)
	(segment
		(start 244.046756 -0.006604)
		(end 244.166136 -0.177292)
		(width 0.14732)
		(layer "In11.Cu")
		(net "DELTA_L_85_5INCH_IN4_DP")
	)
	(segment
		(start 236.145832 0.062484)
		(end 236.265212 -0.108458)
		(width 0.14732)
		(layer "In11.Cu")
		(net "DELTA_L_85_5INCH_IN4_DP")
	)
	(segment
		(start 248.853706 -2.29616)
		(end 249.148346 -2.5908)
		(width 0.14732)
		(layer "In11.Cu")
		(net "DELTA_L_85_5INCH_IN4_DP")
	)
	(segment
		(start 219.65539 -6.328664)
		(end 221.237556 -6.607556)
		(width 0.14732)
		(layer "In11.Cu")
		(net "DELTA_L_85_5INCH_IN4_DP")
	)
	(segment
		(start 236.265212 -0.108458)
		(end 235.233718 -5.95884)
		(width 0.14732)
		(layer "In11.Cu")
		(net "DELTA_L_85_5INCH_IN4_DP")
	)
	(segment
		(start 246.374666 -2.29616)
		(end 248.853706 -2.29616)
		(width 0.14732)
		(layer "In11.Cu")
		(net "DELTA_L_85_5INCH_IN4_DP")
	)
	(segment
		(start 224.393506 -0.122682)
		(end 223.359472 -5.985764)
		(width 0.14732)
		(layer "In11.Cu")
		(net "DELTA_L_85_5INCH_IN4_DP")
	)
	(segment
		(start 212.67928 -1.909064)
		(end 213.360254 -1.7272)
		(width 0.13208)
		(layer "B.Cu")
		(net "DELTA_L_85_5INCH_IN4_DN")
	)
	(segment
		(start 249.82932 -1.909064)
		(end 249.148346 -1.7272)
		(width 0.13208)
		(layer "B.Cu")
		(net "DELTA_L_85_5INCH_IN4_DN")
	)
	(segment
		(start 228.387148 0.281178)
		(end 228.63683 -0.075946)
		(width 0.14732)
		(layer "In11.Cu")
		(net "DELTA_L_85_5INCH_IN4_DN")
	)
	(segment
		(start 226.447604 0.310388)
		(end 226.804728 0.56007)
		(width 0.14732)
		(layer "In11.Cu")
		(net "DELTA_L_85_5INCH_IN4_DN")
	)
	(segment
		(start 221.343474 -6.198108)
		(end 222.494348 0.32766)
		(width 0.14732)
		(layer "In11.Cu")
		(net "DELTA_L_85_5INCH_IN4_DN")
	)
	(segment
		(start 232.347262 0.303022)
		(end 232.597198 -0.053848)
		(width 0.14732)
		(layer "In11.Cu")
		(net "DELTA_L_85_5INCH_IN4_DN")
	)
	(segment
		(start 240.94567 -6.37413)
		(end 241.11585 -6.25475)
		(width 0.14732)
		(layer "In11.Cu")
		(net "DELTA_L_85_5INCH_IN4_DN")
	)
	(segment
		(start 224.683574 -0.05842)
		(end 223.64954 -5.921502)
		(width 0.14732)
		(layer "In11.Cu")
		(net "DELTA_L_85_5INCH_IN4_DN")
	)
	(segment
		(start 221.173294 -6.317488)
		(end 221.343474 -6.198108)
		(width 0.14732)
		(layer "In11.Cu")
		(net "DELTA_L_85_5INCH_IN4_DN")
	)
	(segment
		(start 243.550186 -6.097524)
		(end 244.908578 -6.3373)
		(width 0.14732)
		(layer "In11.Cu")
		(net "DELTA_L_85_5INCH_IN4_DN")
	)
	(segment
		(start 240.503456 -0.091948)
		(end 239.467898 -5.964174)
		(width 0.14732)
		(layer "In11.Cu")
		(net "DELTA_L_85_5INCH_IN4_DN")
	)
	(segment
		(start 239.587278 -6.134608)
		(end 240.94567 -6.37413)
		(width 0.14732)
		(layer "In11.Cu")
		(net "DELTA_L_85_5INCH_IN4_DN")
	)
	(segment
		(start 237.171738 -6.185408)
		(end 238.314484 0.293878)
		(width 0.14732)
		(layer "In11.Cu")
		(net "DELTA_L_85_5INCH_IN4_DN")
	)
	(segment
		(start 230.765096 0.581914)
		(end 232.347262 0.303022)
		(width 0.14732)
		(layer "In11.Cu")
		(net "DELTA_L_85_5INCH_IN4_DN")
	)
	(segment
		(start 246.260874 -2.02184)
		(end 248.853706 -2.02184)
		(width 0.14732)
		(layer "In11.Cu")
		(net "DELTA_L_85_5INCH_IN4_DN")
	)
	(segment
		(start 220.46692 0.241046)
		(end 220.716856 -0.116332)
		(width 0.14732)
		(layer "In11.Cu")
		(net "DELTA_L_85_5INCH_IN4_DN")
	)
	(segment
		(start 226.804728 0.56007)
		(end 228.387148 0.281178)
		(width 0.14732)
		(layer "In11.Cu")
		(net "DELTA_L_85_5INCH_IN4_DN")
	)
	(segment
		(start 213.654894 -2.02184)
		(end 217.482928 -2.02184)
		(width 0.14732)
		(layer "In11.Cu")
		(net "DELTA_L_85_5INCH_IN4_DN")
	)
	(segment
		(start 223.64954 -5.921502)
		(end 223.76892 -6.09219)
		(width 0.14732)
		(layer "In11.Cu")
		(net "DELTA_L_85_5INCH_IN4_DN")
	)
	(segment
		(start 228.63683 -0.075946)
		(end 227.6094 -5.903214)
		(width 0.14732)
		(layer "In11.Cu")
		(net "DELTA_L_85_5INCH_IN4_DN")
	)
	(segment
		(start 243.430806 -5.927344)
		(end 243.550186 -6.097524)
		(width 0.14732)
		(layer "In11.Cu")
		(net "DELTA_L_85_5INCH_IN4_DN")
	)
	(segment
		(start 233.205782 -6.23824)
		(end 234.366308 0.341884)
		(width 0.14732)
		(layer "In11.Cu")
		(net "DELTA_L_85_5INCH_IN4_DN")
	)
	(segment
		(start 241.11585 -6.25475)
		(end 242.266978 0.273304)
		(width 0.14732)
		(layer "In11.Cu")
		(net "DELTA_L_85_5INCH_IN4_DN")
	)
	(segment
		(start 219.814902 -6.07822)
		(end 221.173294 -6.317488)
		(width 0.14732)
		(layer "In11.Cu")
		(net "DELTA_L_85_5INCH_IN4_DN")
	)
	(segment
		(start 227.72878 -6.074156)
		(end 229.087172 -6.313678)
		(width 0.14732)
		(layer "In11.Cu")
		(net "DELTA_L_85_5INCH_IN4_DN")
	)
	(segment
		(start 234.366308 0.341884)
		(end 234.723178 0.592074)
		(width 0.14732)
		(layer "In11.Cu")
		(net "DELTA_L_85_5INCH_IN4_DN")
	)
	(segment
		(start 235.523786 -5.894578)
		(end 235.643166 -6.065012)
		(width 0.14732)
		(layer "In11.Cu")
		(net "DELTA_L_85_5INCH_IN4_DN")
	)
	(segment
		(start 242.266978 0.273304)
		(end 242.624102 0.522986)
		(width 0.14732)
		(layer "In11.Cu")
		(net "DELTA_L_85_5INCH_IN4_DN")
	)
	(segment
		(start 245.079012 -6.21792)
		(end 245.72468 -2.558034)
		(width 0.14732)
		(layer "In11.Cu")
		(net "DELTA_L_85_5INCH_IN4_DN")
	)
	(segment
		(start 245.72468 -2.558034)
		(end 246.260874 -2.02184)
		(width 0.14732)
		(layer "In11.Cu")
		(net "DELTA_L_85_5INCH_IN4_DN")
	)
	(segment
		(start 229.087172 -6.313678)
		(end 229.257352 -6.194552)
		(width 0.14732)
		(layer "In11.Cu")
		(net "DELTA_L_85_5INCH_IN4_DN")
	)
	(segment
		(start 222.494348 0.32766)
		(end 222.850964 0.57785)
		(width 0.14732)
		(layer "In11.Cu")
		(net "DELTA_L_85_5INCH_IN4_DN")
	)
	(segment
		(start 242.735862 0.503174)
		(end 244.206522 0.244094)
		(width 0.14732)
		(layer "In11.Cu")
		(net "DELTA_L_85_5INCH_IN4_DN")
	)
	(segment
		(start 225.297492 -6.212332)
		(end 226.447604 0.310388)
		(width 0.14732)
		(layer "In11.Cu")
		(net "DELTA_L_85_5INCH_IN4_DN")
	)
	(segment
		(start 236.55528 -0.04445)
		(end 235.523786 -5.894578)
		(width 0.14732)
		(layer "In11.Cu")
		(net "DELTA_L_85_5INCH_IN4_DN")
	)
	(segment
		(start 239.467898 -5.964174)
		(end 239.587278 -6.134608)
		(width 0.14732)
		(layer "In11.Cu")
		(net "DELTA_L_85_5INCH_IN4_DN")
	)
	(segment
		(start 218.884246 0.519938)
		(end 220.46692 0.241046)
		(width 0.14732)
		(layer "In11.Cu")
		(net "DELTA_L_85_5INCH_IN4_DN")
	)
	(segment
		(start 235.643166 -6.065012)
		(end 237.001558 -6.304534)
		(width 0.14732)
		(layer "In11.Cu")
		(net "DELTA_L_85_5INCH_IN4_DN")
	)
	(segment
		(start 219.695522 -5.907786)
		(end 219.814902 -6.07822)
		(width 0.14732)
		(layer "In11.Cu")
		(net "DELTA_L_85_5INCH_IN4_DN")
	)
	(segment
		(start 218.52763 0.269748)
		(end 218.884246 0.519938)
		(width 0.14732)
		(layer "In11.Cu")
		(net "DELTA_L_85_5INCH_IN4_DN")
	)
	(segment
		(start 237.001558 -6.304534)
		(end 237.171738 -6.185408)
		(width 0.14732)
		(layer "In11.Cu")
		(net "DELTA_L_85_5INCH_IN4_DN")
	)
	(segment
		(start 222.850964 0.57785)
		(end 224.433638 0.298958)
		(width 0.14732)
		(layer "In11.Cu")
		(net "DELTA_L_85_5INCH_IN4_DN")
	)
	(segment
		(start 242.735862 0.503428)
		(end 242.735862 0.503174)
		(width 0.14732)
		(layer "In11.Cu")
		(net "DELTA_L_85_5INCH_IN4_DN")
	)
	(segment
		(start 244.456204 -0.11303)
		(end 243.430806 -5.927344)
		(width 0.14732)
		(layer "In11.Cu")
		(net "DELTA_L_85_5INCH_IN4_DN")
	)
	(segment
		(start 242.624102 0.522986)
		(end 242.735862 0.503428)
		(width 0.14732)
		(layer "In11.Cu")
		(net "DELTA_L_85_5INCH_IN4_DN")
	)
	(segment
		(start 224.433638 0.298958)
		(end 224.683574 -0.05842)
		(width 0.14732)
		(layer "In11.Cu")
		(net "DELTA_L_85_5INCH_IN4_DN")
	)
	(segment
		(start 229.257352 -6.194552)
		(end 230.407972 0.332232)
		(width 0.14732)
		(layer "In11.Cu")
		(net "DELTA_L_85_5INCH_IN4_DN")
	)
	(segment
		(start 238.314484 0.293878)
		(end 238.671354 0.544068)
		(width 0.14732)
		(layer "In11.Cu")
		(net "DELTA_L_85_5INCH_IN4_DN")
	)
	(segment
		(start 230.407972 0.332232)
		(end 230.765096 0.581914)
		(width 0.14732)
		(layer "In11.Cu")
		(net "DELTA_L_85_5INCH_IN4_DN")
	)
	(segment
		(start 240.253774 0.265176)
		(end 240.503456 -0.091948)
		(width 0.14732)
		(layer "In11.Cu")
		(net "DELTA_L_85_5INCH_IN4_DN")
	)
	(segment
		(start 236.305598 0.312928)
		(end 236.55528 -0.04445)
		(width 0.14732)
		(layer "In11.Cu")
		(net "DELTA_L_85_5INCH_IN4_DN")
	)
	(segment
		(start 223.76892 -6.09219)
		(end 225.127312 -6.331712)
		(width 0.14732)
		(layer "In11.Cu")
		(net "DELTA_L_85_5INCH_IN4_DN")
	)
	(segment
		(start 217.482928 -2.02184)
		(end 218.260676 -1.244092)
		(width 0.14732)
		(layer "In11.Cu")
		(net "DELTA_L_85_5INCH_IN4_DN")
	)
	(segment
		(start 244.206522 0.244094)
		(end 244.456204 -0.11303)
		(width 0.14732)
		(layer "In11.Cu")
		(net "DELTA_L_85_5INCH_IN4_DN")
	)
	(segment
		(start 231.67721 -6.118098)
		(end 233.035602 -6.35762)
		(width 0.14732)
		(layer "In11.Cu")
		(net "DELTA_L_85_5INCH_IN4_DN")
	)
	(segment
		(start 220.716856 -0.116332)
		(end 219.695522 -5.907786)
		(width 0.14732)
		(layer "In11.Cu")
		(net "DELTA_L_85_5INCH_IN4_DN")
	)
	(segment
		(start 213.360254 -1.7272)
		(end 213.654894 -2.02184)
		(width 0.14732)
		(layer "In11.Cu")
		(net "DELTA_L_85_5INCH_IN4_DN")
	)
	(segment
		(start 225.127312 -6.331712)
		(end 225.297492 -6.212332)
		(width 0.14732)
		(layer "In11.Cu")
		(net "DELTA_L_85_5INCH_IN4_DN")
	)
	(segment
		(start 248.853706 -2.02184)
		(end 249.148346 -1.7272)
		(width 0.14732)
		(layer "In11.Cu")
		(net "DELTA_L_85_5INCH_IN4_DN")
	)
	(segment
		(start 238.671354 0.544068)
		(end 240.253774 0.265176)
		(width 0.14732)
		(layer "In11.Cu")
		(net "DELTA_L_85_5INCH_IN4_DN")
	)
	(segment
		(start 244.908578 -6.3373)
		(end 245.079012 -6.21792)
		(width 0.14732)
		(layer "In11.Cu")
		(net "DELTA_L_85_5INCH_IN4_DN")
	)
	(segment
		(start 232.597198 -0.053848)
		(end 231.55783 -5.947918)
		(width 0.14732)
		(layer "In11.Cu")
		(net "DELTA_L_85_5INCH_IN4_DN")
	)
	(segment
		(start 218.260676 -1.244092)
		(end 218.52763 0.269748)
		(width 0.14732)
		(layer "In11.Cu")
		(net "DELTA_L_85_5INCH_IN4_DN")
	)
	(segment
		(start 231.55783 -5.947918)
		(end 231.67721 -6.118098)
		(width 0.14732)
		(layer "In11.Cu")
		(net "DELTA_L_85_5INCH_IN4_DN")
	)
	(segment
		(start 227.6094 -5.903214)
		(end 227.72878 -6.074156)
		(width 0.14732)
		(layer "In11.Cu")
		(net "DELTA_L_85_5INCH_IN4_DN")
	)
	(segment
		(start 233.035602 -6.35762)
		(end 233.205782 -6.23824)
		(width 0.14732)
		(layer "In11.Cu")
		(net "DELTA_L_85_5INCH_IN4_DN")
	)
	(segment
		(start 234.723178 0.592074)
		(end 236.305598 0.312928)
		(width 0.14732)
		(layer "In11.Cu")
		(net "DELTA_L_85_5INCH_IN4_DN")
	)
	(segment
		(start 212.67928 -4.449064)
		(end 213.360254 -4.2672)
		(width 0.13208)
		(layer "F.Cu")
		(net "DELTA_L_85_5INCH_IN3_DP")
	)
	(segment
		(start 249.82932 -4.449064)
		(end 249.148346 -4.2672)
		(width 0.13208)
		(layer "F.Cu")
		(net "DELTA_L_85_5INCH_IN3_DP")
	)
	(segment
		(start 242.266978 -2.266696)
		(end 242.624102 -2.017014)
		(width 0.14732)
		(layer "In6.Cu")
		(net "DELTA_L_85_5INCH_IN3_DP")
	)
	(segment
		(start 237.171738 -8.725408)
		(end 238.314484 -2.246122)
		(width 0.14732)
		(layer "In6.Cu")
		(net "DELTA_L_85_5INCH_IN3_DP")
	)
	(segment
		(start 230.765096 -1.958086)
		(end 232.347262 -2.236978)
		(width 0.14732)
		(layer "In6.Cu")
		(net "DELTA_L_85_5INCH_IN3_DP")
	)
	(segment
		(start 225.297492 -8.752332)
		(end 226.447604 -2.229612)
		(width 0.14732)
		(layer "In6.Cu")
		(net "DELTA_L_85_5INCH_IN3_DP")
	)
	(segment
		(start 223.64954 -8.461502)
		(end 223.76892 -8.63219)
		(width 0.14732)
		(layer "In6.Cu")
		(net "DELTA_L_85_5INCH_IN3_DP")
	)
	(segment
		(start 221.173294 -8.857488)
		(end 221.343474 -8.738108)
		(width 0.14732)
		(layer "In6.Cu")
		(net "DELTA_L_85_5INCH_IN3_DP")
	)
	(segment
		(start 231.55783 -8.487918)
		(end 231.67721 -8.658098)
		(width 0.14732)
		(layer "In6.Cu")
		(net "DELTA_L_85_5INCH_IN3_DP")
	)
	(segment
		(start 237.001558 -8.844534)
		(end 237.171738 -8.725408)
		(width 0.14732)
		(layer "In6.Cu")
		(net "DELTA_L_85_5INCH_IN3_DP")
	)
	(segment
		(start 225.127312 -8.871712)
		(end 225.297492 -8.752332)
		(width 0.14732)
		(layer "In6.Cu")
		(net "DELTA_L_85_5INCH_IN3_DP")
	)
	(segment
		(start 235.643166 -8.605012)
		(end 237.001558 -8.844534)
		(width 0.14732)
		(layer "In6.Cu")
		(net "DELTA_L_85_5INCH_IN3_DP")
	)
	(segment
		(start 234.366308 -2.198116)
		(end 234.723178 -1.947926)
		(width 0.14732)
		(layer "In6.Cu")
		(net "DELTA_L_85_5INCH_IN3_DP")
	)
	(segment
		(start 243.430806 -8.467344)
		(end 243.550186 -8.637524)
		(width 0.14732)
		(layer "In6.Cu")
		(net "DELTA_L_85_5INCH_IN3_DP")
	)
	(segment
		(start 219.814902 -8.61822)
		(end 221.173294 -8.857488)
		(width 0.14732)
		(layer "In6.Cu")
		(net "DELTA_L_85_5INCH_IN3_DP")
	)
	(segment
		(start 235.523786 -8.434578)
		(end 235.643166 -8.605012)
		(width 0.14732)
		(layer "In6.Cu")
		(net "DELTA_L_85_5INCH_IN3_DP")
	)
	(segment
		(start 240.253774 -2.274824)
		(end 240.503456 -2.631948)
		(width 0.14732)
		(layer "In6.Cu")
		(net "DELTA_L_85_5INCH_IN3_DP")
	)
	(segment
		(start 236.305598 -2.227072)
		(end 236.55528 -2.58445)
		(width 0.14732)
		(layer "In6.Cu")
		(net "DELTA_L_85_5INCH_IN3_DP")
	)
	(segment
		(start 226.804728 -1.97993)
		(end 228.387148 -2.258822)
		(width 0.14732)
		(layer "In6.Cu")
		(net "DELTA_L_85_5INCH_IN3_DP")
	)
	(segment
		(start 223.76892 -8.63219)
		(end 225.127312 -8.871712)
		(width 0.14732)
		(layer "In6.Cu")
		(net "DELTA_L_85_5INCH_IN3_DP")
	)
	(segment
		(start 239.587278 -8.674608)
		(end 240.94567 -8.91413)
		(width 0.14732)
		(layer "In6.Cu")
		(net "DELTA_L_85_5INCH_IN3_DP")
	)
	(segment
		(start 240.503456 -2.631948)
		(end 239.467898 -8.504174)
		(width 0.14732)
		(layer "In6.Cu")
		(net "DELTA_L_85_5INCH_IN3_DP")
	)
	(segment
		(start 224.683574 -2.59842)
		(end 223.64954 -8.461502)
		(width 0.14732)
		(layer "In6.Cu")
		(net "DELTA_L_85_5INCH_IN3_DP")
	)
	(segment
		(start 230.407972 -2.207768)
		(end 230.765096 -1.958086)
		(width 0.14732)
		(layer "In6.Cu")
		(net "DELTA_L_85_5INCH_IN3_DP")
	)
	(segment
		(start 233.205782 -8.77824)
		(end 234.366308 -2.198116)
		(width 0.14732)
		(layer "In6.Cu")
		(net "DELTA_L_85_5INCH_IN3_DP")
	)
	(segment
		(start 240.94567 -8.91413)
		(end 241.11585 -8.79475)
		(width 0.14732)
		(layer "In6.Cu")
		(net "DELTA_L_85_5INCH_IN3_DP")
	)
	(segment
		(start 241.11585 -8.79475)
		(end 242.266978 -2.266696)
		(width 0.14732)
		(layer "In6.Cu")
		(net "DELTA_L_85_5INCH_IN3_DP")
	)
	(segment
		(start 232.347262 -2.236978)
		(end 232.597198 -2.593848)
		(width 0.14732)
		(layer "In6.Cu")
		(net "DELTA_L_85_5INCH_IN3_DP")
	)
	(segment
		(start 236.55528 -2.58445)
		(end 235.523786 -8.434578)
		(width 0.14732)
		(layer "In6.Cu")
		(net "DELTA_L_85_5INCH_IN3_DP")
	)
	(segment
		(start 220.46692 -2.298954)
		(end 220.716856 -2.656332)
		(width 0.14732)
		(layer "In6.Cu")
		(net "DELTA_L_85_5INCH_IN3_DP")
	)
	(segment
		(start 243.550186 -8.637524)
		(end 244.908578 -8.8773)
		(width 0.14732)
		(layer "In6.Cu")
		(net "DELTA_L_85_5INCH_IN3_DP")
	)
	(segment
		(start 228.63683 -2.615946)
		(end 227.6094 -8.443214)
		(width 0.14732)
		(layer "In6.Cu")
		(net "DELTA_L_85_5INCH_IN3_DP")
	)
	(segment
		(start 245.72468 -5.098034)
		(end 246.260874 -4.56184)
		(width 0.14732)
		(layer "In6.Cu")
		(net "DELTA_L_85_5INCH_IN3_DP")
	)
	(segment
		(start 232.597198 -2.593848)
		(end 231.55783 -8.487918)
		(width 0.14732)
		(layer "In6.Cu")
		(net "DELTA_L_85_5INCH_IN3_DP")
	)
	(segment
		(start 213.360254 -4.2672)
		(end 213.654894 -4.56184)
		(width 0.14732)
		(layer "In6.Cu")
		(net "DELTA_L_85_5INCH_IN3_DP")
	)
	(segment
		(start 242.735862 -2.036826)
		(end 244.206522 -2.295906)
		(width 0.14732)
		(layer "In6.Cu")
		(net "DELTA_L_85_5INCH_IN3_DP")
	)
	(segment
		(start 242.624102 -2.017014)
		(end 242.735862 -2.036572)
		(width 0.14732)
		(layer "In6.Cu")
		(net "DELTA_L_85_5INCH_IN3_DP")
	)
	(segment
		(start 244.456204 -2.65303)
		(end 243.430806 -8.467344)
		(width 0.14732)
		(layer "In6.Cu")
		(net "DELTA_L_85_5INCH_IN3_DP")
	)
	(segment
		(start 218.52763 -2.270252)
		(end 218.884246 -2.020062)
		(width 0.14732)
		(layer "In6.Cu")
		(net "DELTA_L_85_5INCH_IN3_DP")
	)
	(segment
		(start 222.494348 -2.21234)
		(end 222.850964 -1.96215)
		(width 0.14732)
		(layer "In6.Cu")
		(net "DELTA_L_85_5INCH_IN3_DP")
	)
	(segment
		(start 233.035602 -8.89762)
		(end 233.205782 -8.77824)
		(width 0.14732)
		(layer "In6.Cu")
		(net "DELTA_L_85_5INCH_IN3_DP")
	)
	(segment
		(start 228.387148 -2.258822)
		(end 228.63683 -2.615946)
		(width 0.14732)
		(layer "In6.Cu")
		(net "DELTA_L_85_5INCH_IN3_DP")
	)
	(segment
		(start 229.087172 -8.853678)
		(end 229.257352 -8.734552)
		(width 0.14732)
		(layer "In6.Cu")
		(net "DELTA_L_85_5INCH_IN3_DP")
	)
	(segment
		(start 239.467898 -8.504174)
		(end 239.587278 -8.674608)
		(width 0.14732)
		(layer "In6.Cu")
		(net "DELTA_L_85_5INCH_IN3_DP")
	)
	(segment
		(start 213.654894 -4.56184)
		(end 217.482928 -4.56184)
		(width 0.14732)
		(layer "In6.Cu")
		(net "DELTA_L_85_5INCH_IN3_DP")
	)
	(segment
		(start 224.433638 -2.241042)
		(end 224.683574 -2.59842)
		(width 0.14732)
		(layer "In6.Cu")
		(net "DELTA_L_85_5INCH_IN3_DP")
	)
	(segment
		(start 227.72878 -8.614156)
		(end 229.087172 -8.853678)
		(width 0.14732)
		(layer "In6.Cu")
		(net "DELTA_L_85_5INCH_IN3_DP")
	)
	(segment
		(start 248.853706 -4.56184)
		(end 249.148346 -4.2672)
		(width 0.14732)
		(layer "In6.Cu")
		(net "DELTA_L_85_5INCH_IN3_DP")
	)
	(segment
		(start 218.260676 -3.784092)
		(end 218.52763 -2.270252)
		(width 0.14732)
		(layer "In6.Cu")
		(net "DELTA_L_85_5INCH_IN3_DP")
	)
	(segment
		(start 245.079012 -8.75792)
		(end 245.72468 -5.098034)
		(width 0.14732)
		(layer "In6.Cu")
		(net "DELTA_L_85_5INCH_IN3_DP")
	)
	(segment
		(start 234.723178 -1.947926)
		(end 236.305598 -2.227072)
		(width 0.14732)
		(layer "In6.Cu")
		(net "DELTA_L_85_5INCH_IN3_DP")
	)
	(segment
		(start 238.314484 -2.246122)
		(end 238.671354 -1.995932)
		(width 0.14732)
		(layer "In6.Cu")
		(net "DELTA_L_85_5INCH_IN3_DP")
	)
	(segment
		(start 220.716856 -2.656332)
		(end 219.695522 -8.447786)
		(width 0.14732)
		(layer "In6.Cu")
		(net "DELTA_L_85_5INCH_IN3_DP")
	)
	(segment
		(start 238.671354 -1.995932)
		(end 240.253774 -2.274824)
		(width 0.14732)
		(layer "In6.Cu")
		(net "DELTA_L_85_5INCH_IN3_DP")
	)
	(segment
		(start 242.735862 -2.036572)
		(end 242.735862 -2.036826)
		(width 0.14732)
		(layer "In6.Cu")
		(net "DELTA_L_85_5INCH_IN3_DP")
	)
	(segment
		(start 229.257352 -8.734552)
		(end 230.407972 -2.207768)
		(width 0.14732)
		(layer "In6.Cu")
		(net "DELTA_L_85_5INCH_IN3_DP")
	)
	(segment
		(start 244.206522 -2.295906)
		(end 244.456204 -2.65303)
		(width 0.14732)
		(layer "In6.Cu")
		(net "DELTA_L_85_5INCH_IN3_DP")
	)
	(segment
		(start 221.343474 -8.738108)
		(end 222.494348 -2.21234)
		(width 0.14732)
		(layer "In6.Cu")
		(net "DELTA_L_85_5INCH_IN3_DP")
	)
	(segment
		(start 231.67721 -8.658098)
		(end 233.035602 -8.89762)
		(width 0.14732)
		(layer "In6.Cu")
		(net "DELTA_L_85_5INCH_IN3_DP")
	)
	(segment
		(start 246.260874 -4.56184)
		(end 248.853706 -4.56184)
		(width 0.14732)
		(layer "In6.Cu")
		(net "DELTA_L_85_5INCH_IN3_DP")
	)
	(segment
		(start 227.6094 -8.443214)
		(end 227.72878 -8.614156)
		(width 0.14732)
		(layer "In6.Cu")
		(net "DELTA_L_85_5INCH_IN3_DP")
	)
	(segment
		(start 244.908578 -8.8773)
		(end 245.079012 -8.75792)
		(width 0.14732)
		(layer "In6.Cu")
		(net "DELTA_L_85_5INCH_IN3_DP")
	)
	(segment
		(start 222.850964 -1.96215)
		(end 224.433638 -2.241042)
		(width 0.14732)
		(layer "In6.Cu")
		(net "DELTA_L_85_5INCH_IN3_DP")
	)
	(segment
		(start 219.695522 -8.447786)
		(end 219.814902 -8.61822)
		(width 0.14732)
		(layer "In6.Cu")
		(net "DELTA_L_85_5INCH_IN3_DP")
	)
	(segment
		(start 217.482928 -4.56184)
		(end 218.260676 -3.784092)
		(width 0.14732)
		(layer "In6.Cu")
		(net "DELTA_L_85_5INCH_IN3_DP")
	)
	(segment
		(start 226.447604 -2.229612)
		(end 226.804728 -1.97993)
		(width 0.14732)
		(layer "In6.Cu")
		(net "DELTA_L_85_5INCH_IN3_DP")
	)
	(segment
		(start 218.884246 -2.020062)
		(end 220.46692 -2.298954)
		(width 0.14732)
		(layer "In6.Cu")
		(net "DELTA_L_85_5INCH_IN3_DP")
	)
	(segment
		(start 212.67928 -4.948936)
		(end 213.360254 -5.1308)
		(width 0.13208)
		(layer "F.Cu")
		(net "DELTA_L_85_5INCH_IN3_DN")
	)
	(segment
		(start 249.82932 -4.948936)
		(end 249.148346 -5.1308)
		(width 0.13208)
		(layer "F.Cu")
		(net "DELTA_L_85_5INCH_IN3_DN")
	)
	(segment
		(start 239.17783 -8.568436)
		(end 239.427512 -8.925306)
		(width 0.14732)
		(layer "In6.Cu")
		(net "DELTA_L_85_5INCH_IN3_DN")
	)
	(segment
		(start 219.65539 -8.868664)
		(end 221.237556 -9.147556)
		(width 0.14732)
		(layer "In6.Cu")
		(net "DELTA_L_85_5INCH_IN3_DN")
	)
	(segment
		(start 232.30713 -2.65811)
		(end 231.267762 -8.55218)
		(width 0.14732)
		(layer "In6.Cu")
		(net "DELTA_L_85_5INCH_IN3_DN")
	)
	(segment
		(start 234.616752 -2.357628)
		(end 234.78744 -2.237994)
		(width 0.14732)
		(layer "In6.Cu")
		(net "DELTA_L_85_5INCH_IN3_DN")
	)
	(segment
		(start 221.237556 -9.147556)
		(end 221.594172 -8.897874)
		(width 0.14732)
		(layer "In6.Cu")
		(net "DELTA_L_85_5INCH_IN3_DN")
	)
	(segment
		(start 219.405454 -8.512048)
		(end 219.65539 -8.868664)
		(width 0.14732)
		(layer "In6.Cu")
		(net "DELTA_L_85_5INCH_IN3_DN")
	)
	(segment
		(start 228.227382 -2.50952)
		(end 228.346762 -2.680208)
		(width 0.14732)
		(layer "In6.Cu")
		(net "DELTA_L_85_5INCH_IN3_DN")
	)
	(segment
		(start 223.609408 -8.882634)
		(end 225.191574 -9.16178)
		(width 0.14732)
		(layer "In6.Cu")
		(net "DELTA_L_85_5INCH_IN3_DN")
	)
	(segment
		(start 213.654894 -4.83616)
		(end 217.59672 -4.83616)
		(width 0.14732)
		(layer "In6.Cu")
		(net "DELTA_L_85_5INCH_IN3_DN")
	)
	(segment
		(start 244.97284 -9.167368)
		(end 245.32971 -8.917686)
		(width 0.14732)
		(layer "In6.Cu")
		(net "DELTA_L_85_5INCH_IN3_DN")
	)
	(segment
		(start 227.319332 -8.507476)
		(end 227.569014 -8.8646)
		(width 0.14732)
		(layer "In6.Cu")
		(net "DELTA_L_85_5INCH_IN3_DN")
	)
	(segment
		(start 226.698302 -2.389378)
		(end 226.86899 -2.269998)
		(width 0.14732)
		(layer "In6.Cu")
		(net "DELTA_L_85_5INCH_IN3_DN")
	)
	(segment
		(start 224.273872 -2.49174)
		(end 224.393506 -2.662682)
		(width 0.14732)
		(layer "In6.Cu")
		(net "DELTA_L_85_5INCH_IN3_DN")
	)
	(segment
		(start 235.4834 -8.85571)
		(end 237.06582 -9.134602)
		(width 0.14732)
		(layer "In6.Cu")
		(net "DELTA_L_85_5INCH_IN3_DN")
	)
	(segment
		(start 231.517444 -8.908796)
		(end 233.099864 -9.187688)
		(width 0.14732)
		(layer "In6.Cu")
		(net "DELTA_L_85_5INCH_IN3_DN")
	)
	(segment
		(start 235.233718 -8.49884)
		(end 235.4834 -8.85571)
		(width 0.14732)
		(layer "In6.Cu")
		(net "DELTA_L_85_5INCH_IN3_DN")
	)
	(segment
		(start 245.97995 -5.230876)
		(end 246.374666 -4.83616)
		(width 0.14732)
		(layer "In6.Cu")
		(net "DELTA_L_85_5INCH_IN3_DN")
	)
	(segment
		(start 234.78744 -2.237994)
		(end 236.145832 -2.477516)
		(width 0.14732)
		(layer "In6.Cu")
		(net "DELTA_L_85_5INCH_IN3_DN")
	)
	(segment
		(start 229.151434 -9.143746)
		(end 229.507796 -8.894064)
		(width 0.14732)
		(layer "In6.Cu")
		(net "DELTA_L_85_5INCH_IN3_DN")
	)
	(segment
		(start 228.346762 -2.680208)
		(end 227.319332 -8.507476)
		(width 0.14732)
		(layer "In6.Cu")
		(net "DELTA_L_85_5INCH_IN3_DN")
	)
	(segment
		(start 243.140738 -8.531606)
		(end 243.39042 -8.888222)
		(width 0.14732)
		(layer "In6.Cu")
		(net "DELTA_L_85_5INCH_IN3_DN")
	)
	(segment
		(start 238.564928 -2.405634)
		(end 238.735616 -2.286)
		(width 0.14732)
		(layer "In6.Cu")
		(net "DELTA_L_85_5INCH_IN3_DN")
	)
	(segment
		(start 218.948762 -2.31013)
		(end 220.307154 -2.549652)
		(width 0.14732)
		(layer "In6.Cu")
		(net "DELTA_L_85_5INCH_IN3_DN")
	)
	(segment
		(start 244.166136 -2.717292)
		(end 243.140738 -8.531606)
		(width 0.14732)
		(layer "In6.Cu")
		(net "DELTA_L_85_5INCH_IN3_DN")
	)
	(segment
		(start 248.853706 -4.83616)
		(end 249.148346 -5.1308)
		(width 0.14732)
		(layer "In6.Cu")
		(net "DELTA_L_85_5INCH_IN3_DN")
	)
	(segment
		(start 240.094008 -2.525522)
		(end 240.213388 -2.69621)
		(width 0.14732)
		(layer "In6.Cu")
		(net "DELTA_L_85_5INCH_IN3_DN")
	)
	(segment
		(start 242.688364 -2.307082)
		(end 244.046756 -2.546604)
		(width 0.14732)
		(layer "In6.Cu")
		(net "DELTA_L_85_5INCH_IN3_DN")
	)
	(segment
		(start 232.18775 -2.487676)
		(end 232.30713 -2.65811)
		(width 0.14732)
		(layer "In6.Cu")
		(net "DELTA_L_85_5INCH_IN3_DN")
	)
	(segment
		(start 230.65867 -2.367534)
		(end 230.829358 -2.248154)
		(width 0.14732)
		(layer "In6.Cu")
		(net "DELTA_L_85_5INCH_IN3_DN")
	)
	(segment
		(start 222.91548 -2.252218)
		(end 224.273872 -2.49174)
		(width 0.14732)
		(layer "In6.Cu")
		(net "DELTA_L_85_5INCH_IN3_DN")
	)
	(segment
		(start 245.32971 -8.917686)
		(end 245.97995 -5.230876)
		(width 0.14732)
		(layer "In6.Cu")
		(net "DELTA_L_85_5INCH_IN3_DN")
	)
	(segment
		(start 226.86899 -2.269998)
		(end 228.227382 -2.50952)
		(width 0.14732)
		(layer "In6.Cu")
		(net "DELTA_L_85_5INCH_IN3_DN")
	)
	(segment
		(start 237.06582 -9.134602)
		(end 237.422182 -8.88492)
		(width 0.14732)
		(layer "In6.Cu")
		(net "DELTA_L_85_5INCH_IN3_DN")
	)
	(segment
		(start 222.745046 -2.371852)
		(end 222.91548 -2.252218)
		(width 0.14732)
		(layer "In6.Cu")
		(net "DELTA_L_85_5INCH_IN3_DN")
	)
	(segment
		(start 221.594172 -8.897874)
		(end 222.745046 -2.371852)
		(width 0.14732)
		(layer "In6.Cu")
		(net "DELTA_L_85_5INCH_IN3_DN")
	)
	(segment
		(start 227.569014 -8.8646)
		(end 229.151434 -9.143746)
		(width 0.14732)
		(layer "In6.Cu")
		(net "DELTA_L_85_5INCH_IN3_DN")
	)
	(segment
		(start 223.359472 -8.525764)
		(end 223.609408 -8.882634)
		(width 0.14732)
		(layer "In6.Cu")
		(net "DELTA_L_85_5INCH_IN3_DN")
	)
	(segment
		(start 246.374666 -4.83616)
		(end 248.853706 -4.83616)
		(width 0.14732)
		(layer "In6.Cu")
		(net "DELTA_L_85_5INCH_IN3_DN")
	)
	(segment
		(start 220.426788 -2.720594)
		(end 219.405454 -8.512048)
		(width 0.14732)
		(layer "In6.Cu")
		(net "DELTA_L_85_5INCH_IN3_DN")
	)
	(segment
		(start 233.099864 -9.187688)
		(end 233.45648 -8.938006)
		(width 0.14732)
		(layer "In6.Cu")
		(net "DELTA_L_85_5INCH_IN3_DN")
	)
	(segment
		(start 244.046756 -2.546604)
		(end 244.166136 -2.717292)
		(width 0.14732)
		(layer "In6.Cu")
		(net "DELTA_L_85_5INCH_IN3_DN")
	)
	(segment
		(start 229.507796 -8.894064)
		(end 230.65867 -2.367534)
		(width 0.14732)
		(layer "In6.Cu")
		(net "DELTA_L_85_5INCH_IN3_DN")
	)
	(segment
		(start 237.422182 -8.88492)
		(end 238.564928 -2.405634)
		(width 0.14732)
		(layer "In6.Cu")
		(net "DELTA_L_85_5INCH_IN3_DN")
	)
	(segment
		(start 233.45648 -8.938006)
		(end 234.616752 -2.357628)
		(width 0.14732)
		(layer "In6.Cu")
		(net "DELTA_L_85_5INCH_IN3_DN")
	)
	(segment
		(start 231.267762 -8.55218)
		(end 231.517444 -8.908796)
		(width 0.14732)
		(layer "In6.Cu")
		(net "DELTA_L_85_5INCH_IN3_DN")
	)
	(segment
		(start 218.778328 -2.429764)
		(end 218.948762 -2.31013)
		(width 0.14732)
		(layer "In6.Cu")
		(net "DELTA_L_85_5INCH_IN3_DN")
	)
	(segment
		(start 239.427512 -8.925306)
		(end 241.009932 -9.204198)
		(width 0.14732)
		(layer "In6.Cu")
		(net "DELTA_L_85_5INCH_IN3_DN")
	)
	(segment
		(start 241.366548 -8.954516)
		(end 242.517676 -2.426462)
		(width 0.14732)
		(layer "In6.Cu")
		(net "DELTA_L_85_5INCH_IN3_DN")
	)
	(segment
		(start 242.517676 -2.426462)
		(end 242.688364 -2.307082)
		(width 0.14732)
		(layer "In6.Cu")
		(net "DELTA_L_85_5INCH_IN3_DN")
	)
	(segment
		(start 225.54819 -8.912098)
		(end 226.698302 -2.389378)
		(width 0.14732)
		(layer "In6.Cu")
		(net "DELTA_L_85_5INCH_IN3_DN")
	)
	(segment
		(start 236.265212 -2.648458)
		(end 235.233718 -8.49884)
		(width 0.14732)
		(layer "In6.Cu")
		(net "DELTA_L_85_5INCH_IN3_DN")
	)
	(segment
		(start 241.009932 -9.204198)
		(end 241.366548 -8.954516)
		(width 0.14732)
		(layer "In6.Cu")
		(net "DELTA_L_85_5INCH_IN3_DN")
	)
	(segment
		(start 236.145832 -2.477516)
		(end 236.265212 -2.648458)
		(width 0.14732)
		(layer "In6.Cu")
		(net "DELTA_L_85_5INCH_IN3_DN")
	)
	(segment
		(start 240.213388 -2.69621)
		(end 239.17783 -8.568436)
		(width 0.14732)
		(layer "In6.Cu")
		(net "DELTA_L_85_5INCH_IN3_DN")
	)
	(segment
		(start 225.191574 -9.16178)
		(end 225.54819 -8.912098)
		(width 0.14732)
		(layer "In6.Cu")
		(net "DELTA_L_85_5INCH_IN3_DN")
	)
	(segment
		(start 213.360254 -5.1308)
		(end 213.654894 -4.83616)
		(width 0.14732)
		(layer "In6.Cu")
		(net "DELTA_L_85_5INCH_IN3_DN")
	)
	(segment
		(start 238.735616 -2.286)
		(end 240.094008 -2.525522)
		(width 0.14732)
		(layer "In6.Cu")
		(net "DELTA_L_85_5INCH_IN3_DN")
	)
	(segment
		(start 218.515946 -3.916934)
		(end 218.778328 -2.429764)
		(width 0.14732)
		(layer "In6.Cu")
		(net "DELTA_L_85_5INCH_IN3_DN")
	)
	(segment
		(start 220.307154 -2.549652)
		(end 220.426788 -2.720594)
		(width 0.14732)
		(layer "In6.Cu")
		(net "DELTA_L_85_5INCH_IN3_DN")
	)
	(segment
		(start 243.39042 -8.888222)
		(end 244.97284 -9.167368)
		(width 0.14732)
		(layer "In6.Cu")
		(net "DELTA_L_85_5INCH_IN3_DN")
	)
	(segment
		(start 217.59672 -4.83616)
		(end 218.515946 -3.916934)
		(width 0.14732)
		(layer "In6.Cu")
		(net "DELTA_L_85_5INCH_IN3_DN")
	)
	(segment
		(start 224.393506 -2.662682)
		(end 223.359472 -8.525764)
		(width 0.14732)
		(layer "In6.Cu")
		(net "DELTA_L_85_5INCH_IN3_DN")
	)
	(segment
		(start 230.829358 -2.248154)
		(end 232.18775 -2.487676)
		(width 0.14732)
		(layer "In6.Cu")
		(net "DELTA_L_85_5INCH_IN3_DN")
	)
	(segment
		(start 340.124034 5.71373)
		(end 340.805008 5.895594)
		(width 0.13208)
		(layer "F.Cu")
		(net "DELTA_L_85_5INCH_IN2_DP")
	)
	(segment
		(start 377.274074 5.71373)
		(end 376.5931 5.895594)
		(width 0.13208)
		(layer "F.Cu")
		(net "DELTA_L_85_5INCH_IN2_DP")
	)
	(segment
		(start 355.054154 1.71958)
		(end 355.173534 1.548638)
		(width 0.14732)
		(layer "In4.Cu")
		(net "DELTA_L_85_5INCH_IN2_DP")
	)
	(segment
		(start 362.96854 1.728216)
		(end 363.08792 1.557782)
		(width 0.14732)
		(layer "In4.Cu")
		(net "DELTA_L_85_5INCH_IN2_DP")
	)
	(segment
		(start 370.068856 8.14578)
		(end 370.180616 8.126222)
		(width 0.14732)
		(layer "In4.Cu")
		(net "DELTA_L_85_5INCH_IN2_DP")
	)
	(segment
		(start 365.759238 7.916672)
		(end 366.116108 8.166862)
		(width 0.14732)
		(layer "In4.Cu")
		(net "DELTA_L_85_5INCH_IN2_DP")
	)
	(segment
		(start 366.912652 1.65862)
		(end 367.032032 1.488186)
		(width 0.14732)
		(layer "In4.Cu")
		(net "DELTA_L_85_5INCH_IN2_DP")
	)
	(segment
		(start 359.121964 1.504696)
		(end 360.480356 1.265174)
		(width 0.14732)
		(layer "In4.Cu")
		(net "DELTA_L_85_5INCH_IN2_DP")
	)
	(segment
		(start 359.002584 1.674876)
		(end 359.121964 1.504696)
		(width 0.14732)
		(layer "In4.Cu")
		(net "DELTA_L_85_5INCH_IN2_DP")
	)
	(segment
		(start 351.878392 7.921752)
		(end 352.128328 7.564374)
		(width 0.14732)
		(layer "In4.Cu")
		(net "DELTA_L_85_5INCH_IN2_DP")
	)
	(segment
		(start 370.87556 1.69545)
		(end 370.99494 1.52527)
		(width 0.14732)
		(layer "In4.Cu")
		(net "DELTA_L_85_5INCH_IN2_DP")
	)
	(segment
		(start 349.939102 7.950454)
		(end 350.295718 8.200644)
		(width 0.14732)
		(layer "In4.Cu")
		(net "DELTA_L_85_5INCH_IN2_DP")
	)
	(segment
		(start 356.531926 1.309116)
		(end 356.702106 1.428242)
		(width 0.14732)
		(layer "In4.Cu")
		(net "DELTA_L_85_5INCH_IN2_DP")
	)
	(segment
		(start 360.650536 1.384554)
		(end 361.811062 7.964678)
		(width 0.14732)
		(layer "In4.Cu")
		(net "DELTA_L_85_5INCH_IN2_DP")
	)
	(segment
		(start 358.20985 8.204708)
		(end 359.792016 7.925816)
		(width 0.14732)
		(layer "In4.Cu")
		(net "DELTA_L_85_5INCH_IN2_DP")
	)
	(segment
		(start 353.892358 7.933182)
		(end 354.249482 8.182864)
		(width 0.14732)
		(layer "In4.Cu")
		(net "DELTA_L_85_5INCH_IN2_DP")
	)
	(segment
		(start 368.390424 1.248664)
		(end 368.560604 1.368044)
		(width 0.14732)
		(layer "In4.Cu")
		(net "DELTA_L_85_5INCH_IN2_DP")
	)
	(segment
		(start 370.180616 8.125968)
		(end 371.651276 7.866888)
		(width 0.14732)
		(layer "In4.Cu")
		(net "DELTA_L_85_5INCH_IN2_DP")
	)
	(segment
		(start 370.180616 8.126222)
		(end 370.180616 8.125968)
		(width 0.14732)
		(layer "In4.Cu")
		(net "DELTA_L_85_5INCH_IN2_DP")
	)
	(segment
		(start 348.618048 1.305306)
		(end 348.788228 1.424686)
		(width 0.14732)
		(layer "In4.Cu")
		(net "DELTA_L_85_5INCH_IN2_DP")
	)
	(segment
		(start 354.249482 8.182864)
		(end 355.831902 7.903972)
		(width 0.14732)
		(layer "In4.Cu")
		(net "DELTA_L_85_5INCH_IN2_DP")
	)
	(segment
		(start 361.811062 7.964678)
		(end 362.167932 8.214868)
		(width 0.14732)
		(layer "In4.Cu")
		(net "DELTA_L_85_5INCH_IN2_DP")
	)
	(segment
		(start 352.128328 7.564374)
		(end 351.094294 1.701292)
		(width 0.14732)
		(layer "In4.Cu")
		(net "DELTA_L_85_5INCH_IN2_DP")
	)
	(segment
		(start 347.259656 1.544574)
		(end 348.618048 1.305306)
		(width 0.14732)
		(layer "In4.Cu")
		(net "DELTA_L_85_5INCH_IN2_DP")
	)
	(segment
		(start 357.852726 7.955026)
		(end 358.20985 8.204708)
		(width 0.14732)
		(layer "In4.Cu")
		(net "DELTA_L_85_5INCH_IN2_DP")
	)
	(segment
		(start 363.08792 1.557782)
		(end 364.446312 1.31826)
		(width 0.14732)
		(layer "In4.Cu")
		(net "DELTA_L_85_5INCH_IN2_DP")
	)
	(segment
		(start 345.70543 6.378702)
		(end 345.972384 7.892542)
		(width 0.14732)
		(layer "In4.Cu")
		(net "DELTA_L_85_5INCH_IN2_DP")
	)
	(segment
		(start 370.99494 1.52527)
		(end 372.353332 1.285494)
		(width 0.14732)
		(layer "In4.Cu")
		(net "DELTA_L_85_5INCH_IN2_DP")
	)
	(segment
		(start 373.705628 5.600954)
		(end 376.29846 5.600954)
		(width 0.14732)
		(layer "In4.Cu")
		(net "DELTA_L_85_5INCH_IN2_DP")
	)
	(segment
		(start 367.032032 1.488186)
		(end 368.390424 1.248664)
		(width 0.14732)
		(layer "In4.Cu")
		(net "DELTA_L_85_5INCH_IN2_DP")
	)
	(segment
		(start 369.711732 7.896098)
		(end 370.068856 8.14578)
		(width 0.14732)
		(layer "In4.Cu")
		(net "DELTA_L_85_5INCH_IN2_DP")
	)
	(segment
		(start 345.972384 7.892542)
		(end 346.329 8.142732)
		(width 0.14732)
		(layer "In4.Cu")
		(net "DELTA_L_85_5INCH_IN2_DP")
	)
	(segment
		(start 360.041952 7.568946)
		(end 359.002584 1.674876)
		(width 0.14732)
		(layer "In4.Cu")
		(net "DELTA_L_85_5INCH_IN2_DP")
	)
	(segment
		(start 362.167932 8.214868)
		(end 363.750352 7.935722)
		(width 0.14732)
		(layer "In4.Cu")
		(net "DELTA_L_85_5INCH_IN2_DP")
	)
	(segment
		(start 367.94821 7.530846)
		(end 366.912652 1.65862)
		(width 0.14732)
		(layer "In4.Cu")
		(net "DELTA_L_85_5INCH_IN2_DP")
	)
	(segment
		(start 366.116108 8.166862)
		(end 367.698528 7.88797)
		(width 0.14732)
		(layer "In4.Cu")
		(net "DELTA_L_85_5INCH_IN2_DP")
	)
	(segment
		(start 351.213674 1.530604)
		(end 352.572066 1.291082)
		(width 0.14732)
		(layer "In4.Cu")
		(net "DELTA_L_85_5INCH_IN2_DP")
	)
	(segment
		(start 376.29846 5.600954)
		(end 376.5931 5.895594)
		(width 0.14732)
		(layer "In4.Cu")
		(net "DELTA_L_85_5INCH_IN2_DP")
	)
	(segment
		(start 348.16161 7.506462)
		(end 347.140276 1.715008)
		(width 0.14732)
		(layer "In4.Cu")
		(net "DELTA_L_85_5INCH_IN2_DP")
	)
	(segment
		(start 356.702106 1.428242)
		(end 357.852726 7.955026)
		(width 0.14732)
		(layer "In4.Cu")
		(net "DELTA_L_85_5INCH_IN2_DP")
	)
	(segment
		(start 355.831902 7.903972)
		(end 356.081584 7.546848)
		(width 0.14732)
		(layer "In4.Cu")
		(net "DELTA_L_85_5INCH_IN2_DP")
	)
	(segment
		(start 351.094294 1.701292)
		(end 351.213674 1.530604)
		(width 0.14732)
		(layer "In4.Cu")
		(net "DELTA_L_85_5INCH_IN2_DP")
	)
	(segment
		(start 368.560604 1.368044)
		(end 369.711732 7.896098)
		(width 0.14732)
		(layer "In4.Cu")
		(net "DELTA_L_85_5INCH_IN2_DP")
	)
	(segment
		(start 344.927682 5.600954)
		(end 345.70543 6.378702)
		(width 0.14732)
		(layer "In4.Cu")
		(net "DELTA_L_85_5INCH_IN2_DP")
	)
	(segment
		(start 372.353332 1.285494)
		(end 372.523766 1.404874)
		(width 0.14732)
		(layer "In4.Cu")
		(net "DELTA_L_85_5INCH_IN2_DP")
	)
	(segment
		(start 359.792016 7.925816)
		(end 360.041952 7.568946)
		(width 0.14732)
		(layer "In4.Cu")
		(net "DELTA_L_85_5INCH_IN2_DP")
	)
	(segment
		(start 371.900958 7.509764)
		(end 370.87556 1.69545)
		(width 0.14732)
		(layer "In4.Cu")
		(net "DELTA_L_85_5INCH_IN2_DP")
	)
	(segment
		(start 371.651276 7.866888)
		(end 371.900958 7.509764)
		(width 0.14732)
		(layer "In4.Cu")
		(net "DELTA_L_85_5INCH_IN2_DP")
	)
	(segment
		(start 355.173534 1.548638)
		(end 356.531926 1.309116)
		(width 0.14732)
		(layer "In4.Cu")
		(net "DELTA_L_85_5INCH_IN2_DP")
	)
	(segment
		(start 360.480356 1.265174)
		(end 360.650536 1.384554)
		(width 0.14732)
		(layer "In4.Cu")
		(net "DELTA_L_85_5INCH_IN2_DP")
	)
	(segment
		(start 367.698528 7.88797)
		(end 367.94821 7.530846)
		(width 0.14732)
		(layer "In4.Cu")
		(net "DELTA_L_85_5INCH_IN2_DP")
	)
	(segment
		(start 348.788228 1.424686)
		(end 349.939102 7.950454)
		(width 0.14732)
		(layer "In4.Cu")
		(net "DELTA_L_85_5INCH_IN2_DP")
	)
	(segment
		(start 340.805008 5.895594)
		(end 341.099648 5.600954)
		(width 0.14732)
		(layer "In4.Cu")
		(net "DELTA_L_85_5INCH_IN2_DP")
	)
	(segment
		(start 373.169434 5.06476)
		(end 373.705628 5.600954)
		(width 0.14732)
		(layer "In4.Cu")
		(net "DELTA_L_85_5INCH_IN2_DP")
	)
	(segment
		(start 350.295718 8.200644)
		(end 351.878392 7.921752)
		(width 0.14732)
		(layer "In4.Cu")
		(net "DELTA_L_85_5INCH_IN2_DP")
	)
	(segment
		(start 352.572066 1.291082)
		(end 352.742246 1.410462)
		(width 0.14732)
		(layer "In4.Cu")
		(net "DELTA_L_85_5INCH_IN2_DP")
	)
	(segment
		(start 364.616492 1.437386)
		(end 365.759238 7.916672)
		(width 0.14732)
		(layer "In4.Cu")
		(net "DELTA_L_85_5INCH_IN2_DP")
	)
	(segment
		(start 341.099648 5.600954)
		(end 344.927682 5.600954)
		(width 0.14732)
		(layer "In4.Cu")
		(net "DELTA_L_85_5INCH_IN2_DP")
	)
	(segment
		(start 364.000034 7.578344)
		(end 362.96854 1.728216)
		(width 0.14732)
		(layer "In4.Cu")
		(net "DELTA_L_85_5INCH_IN2_DP")
	)
	(segment
		(start 364.446312 1.31826)
		(end 364.616492 1.437386)
		(width 0.14732)
		(layer "In4.Cu")
		(net "DELTA_L_85_5INCH_IN2_DP")
	)
	(segment
		(start 347.140276 1.715008)
		(end 347.259656 1.544574)
		(width 0.14732)
		(layer "In4.Cu")
		(net "DELTA_L_85_5INCH_IN2_DP")
	)
	(segment
		(start 346.329 8.142732)
		(end 347.911674 7.86384)
		(width 0.14732)
		(layer "In4.Cu")
		(net "DELTA_L_85_5INCH_IN2_DP")
	)
	(segment
		(start 347.911674 7.86384)
		(end 348.16161 7.506462)
		(width 0.14732)
		(layer "In4.Cu")
		(net "DELTA_L_85_5INCH_IN2_DP")
	)
	(segment
		(start 356.081584 7.546848)
		(end 355.054154 1.71958)
		(width 0.14732)
		(layer "In4.Cu")
		(net "DELTA_L_85_5INCH_IN2_DP")
	)
	(segment
		(start 352.742246 1.410462)
		(end 353.892358 7.933182)
		(width 0.14732)
		(layer "In4.Cu")
		(net "DELTA_L_85_5INCH_IN2_DP")
	)
	(segment
		(start 363.750352 7.935722)
		(end 364.000034 7.578344)
		(width 0.14732)
		(layer "In4.Cu")
		(net "DELTA_L_85_5INCH_IN2_DP")
	)
	(segment
		(start 372.523766 1.404874)
		(end 373.169434 5.06476)
		(width 0.14732)
		(layer "In4.Cu")
		(net "DELTA_L_85_5INCH_IN2_DP")
	)
	(segment
		(start 340.124034 5.213858)
		(end 340.805008 5.031994)
		(width 0.13208)
		(layer "F.Cu")
		(net "DELTA_L_85_5INCH_IN2_DN")
	)
	(segment
		(start 377.274074 5.213858)
		(end 376.5931 5.031994)
		(width 0.13208)
		(layer "F.Cu")
		(net "DELTA_L_85_5INCH_IN2_DN")
	)
	(segment
		(start 370.835174 1.274572)
		(end 372.417594 0.995426)
		(width 0.14732)
		(layer "In4.Cu")
		(net "DELTA_L_85_5INCH_IN2_DN")
	)
	(segment
		(start 376.29846 5.326634)
		(end 376.5931 5.031994)
		(width 0.14732)
		(layer "In4.Cu")
		(net "DELTA_L_85_5INCH_IN2_DN")
	)
	(segment
		(start 360.901234 1.224788)
		(end 362.061506 7.805166)
		(width 0.14732)
		(layer "In4.Cu")
		(net "DELTA_L_85_5INCH_IN2_DN")
	)
	(segment
		(start 372.417594 0.995426)
		(end 372.774464 1.245108)
		(width 0.14732)
		(layer "In4.Cu")
		(net "DELTA_L_85_5INCH_IN2_DN")
	)
	(segment
		(start 363.590586 7.685278)
		(end 363.709966 7.514336)
		(width 0.14732)
		(layer "In4.Cu")
		(net "DELTA_L_85_5INCH_IN2_DN")
	)
	(segment
		(start 341.099648 5.326634)
		(end 345.041474 5.326634)
		(width 0.14732)
		(layer "In4.Cu")
		(net "DELTA_L_85_5INCH_IN2_DN")
	)
	(segment
		(start 351.718626 7.671054)
		(end 351.83826 7.500112)
		(width 0.14732)
		(layer "In4.Cu")
		(net "DELTA_L_85_5INCH_IN2_DN")
	)
	(segment
		(start 362.928154 1.307084)
		(end 364.510574 1.028192)
		(width 0.14732)
		(layer "In4.Cu")
		(net "DELTA_L_85_5INCH_IN2_DN")
	)
	(segment
		(start 348.68231 1.015238)
		(end 349.038926 1.26492)
		(width 0.14732)
		(layer "In4.Cu")
		(net "DELTA_L_85_5INCH_IN2_DN")
	)
	(segment
		(start 373.424704 4.931918)
		(end 373.81942 5.326634)
		(width 0.14732)
		(layer "In4.Cu")
		(net "DELTA_L_85_5INCH_IN2_DN")
	)
	(segment
		(start 345.9607 6.24586)
		(end 346.223082 7.73303)
		(width 0.14732)
		(layer "In4.Cu")
		(net "DELTA_L_85_5INCH_IN2_DN")
	)
	(segment
		(start 354.143056 7.773416)
		(end 354.313744 7.892796)
		(width 0.14732)
		(layer "In4.Cu")
		(net "DELTA_L_85_5INCH_IN2_DN")
	)
	(segment
		(start 340.805008 5.031994)
		(end 341.099648 5.326634)
		(width 0.14732)
		(layer "In4.Cu")
		(net "DELTA_L_85_5INCH_IN2_DN")
	)
	(segment
		(start 366.009682 7.75716)
		(end 366.18037 7.876794)
		(width 0.14732)
		(layer "In4.Cu")
		(net "DELTA_L_85_5INCH_IN2_DN")
	)
	(segment
		(start 347.751908 7.613142)
		(end 347.871542 7.4422)
		(width 0.14732)
		(layer "In4.Cu")
		(net "DELTA_L_85_5INCH_IN2_DN")
	)
	(segment
		(start 358.274112 7.91464)
		(end 359.632504 7.675118)
		(width 0.14732)
		(layer "In4.Cu")
		(net "DELTA_L_85_5INCH_IN2_DN")
	)
	(segment
		(start 349.038926 1.26492)
		(end 350.1898 7.790942)
		(width 0.14732)
		(layer "In4.Cu")
		(net "DELTA_L_85_5INCH_IN2_DN")
	)
	(segment
		(start 362.678472 1.663954)
		(end 362.928154 1.307084)
		(width 0.14732)
		(layer "In4.Cu")
		(net "DELTA_L_85_5INCH_IN2_DN")
	)
	(segment
		(start 352.992944 1.250696)
		(end 354.143056 7.773416)
		(width 0.14732)
		(layer "In4.Cu")
		(net "DELTA_L_85_5INCH_IN2_DN")
	)
	(segment
		(start 352.636328 1.001014)
		(end 352.992944 1.250696)
		(width 0.14732)
		(layer "In4.Cu")
		(net "DELTA_L_85_5INCH_IN2_DN")
	)
	(segment
		(start 359.751884 7.504684)
		(end 358.712516 1.610614)
		(width 0.14732)
		(layer "In4.Cu")
		(net "DELTA_L_85_5INCH_IN2_DN")
	)
	(segment
		(start 368.454686 0.958596)
		(end 368.811302 1.208278)
		(width 0.14732)
		(layer "In4.Cu")
		(net "DELTA_L_85_5INCH_IN2_DN")
	)
	(segment
		(start 350.804226 1.63703)
		(end 351.054162 1.28016)
		(width 0.14732)
		(layer "In4.Cu")
		(net "DELTA_L_85_5INCH_IN2_DN")
	)
	(segment
		(start 371.49151 7.61619)
		(end 371.61089 7.445502)
		(width 0.14732)
		(layer "In4.Cu")
		(net "DELTA_L_85_5INCH_IN2_DN")
	)
	(segment
		(start 346.850208 1.650746)
		(end 347.100144 1.29413)
		(width 0.14732)
		(layer "In4.Cu")
		(net "DELTA_L_85_5INCH_IN2_DN")
	)
	(segment
		(start 366.872266 1.237488)
		(end 368.454686 0.958596)
		(width 0.14732)
		(layer "In4.Cu")
		(net "DELTA_L_85_5INCH_IN2_DN")
	)
	(segment
		(start 350.1898 7.790942)
		(end 350.360234 7.910576)
		(width 0.14732)
		(layer "In4.Cu")
		(net "DELTA_L_85_5INCH_IN2_DN")
	)
	(segment
		(start 351.054162 1.28016)
		(end 352.636328 1.001014)
		(width 0.14732)
		(layer "In4.Cu")
		(net "DELTA_L_85_5INCH_IN2_DN")
	)
	(segment
		(start 367.658142 7.466584)
		(end 366.622584 1.594358)
		(width 0.14732)
		(layer "In4.Cu")
		(net "DELTA_L_85_5INCH_IN2_DN")
	)
	(segment
		(start 370.133118 7.855712)
		(end 371.49151 7.61619)
		(width 0.14732)
		(layer "In4.Cu")
		(net "DELTA_L_85_5INCH_IN2_DN")
	)
	(segment
		(start 355.013768 1.298194)
		(end 356.596188 1.019048)
		(width 0.14732)
		(layer "In4.Cu")
		(net "DELTA_L_85_5INCH_IN2_DN")
	)
	(segment
		(start 359.632504 7.675118)
		(end 359.751884 7.504684)
		(width 0.14732)
		(layer "In4.Cu")
		(net "DELTA_L_85_5INCH_IN2_DN")
	)
	(segment
		(start 364.866936 1.277874)
		(end 366.009682 7.75716)
		(width 0.14732)
		(layer "In4.Cu")
		(net "DELTA_L_85_5INCH_IN2_DN")
	)
	(segment
		(start 351.83826 7.500112)
		(end 350.804226 1.63703)
		(width 0.14732)
		(layer "In4.Cu")
		(net "DELTA_L_85_5INCH_IN2_DN")
	)
	(segment
		(start 354.764086 1.655318)
		(end 355.013768 1.298194)
		(width 0.14732)
		(layer "In4.Cu")
		(net "DELTA_L_85_5INCH_IN2_DN")
	)
	(segment
		(start 347.100144 1.29413)
		(end 348.68231 1.015238)
		(width 0.14732)
		(layer "In4.Cu")
		(net "DELTA_L_85_5INCH_IN2_DN")
	)
	(segment
		(start 355.791516 7.482586)
		(end 354.764086 1.655318)
		(width 0.14732)
		(layer "In4.Cu")
		(net "DELTA_L_85_5INCH_IN2_DN")
	)
	(segment
		(start 346.393516 7.852664)
		(end 347.751908 7.613142)
		(width 0.14732)
		(layer "In4.Cu")
		(net "DELTA_L_85_5INCH_IN2_DN")
	)
	(segment
		(start 356.95255 1.26873)
		(end 358.103424 7.79526)
		(width 0.14732)
		(layer "In4.Cu")
		(net "DELTA_L_85_5INCH_IN2_DN")
	)
	(segment
		(start 362.061506 7.805166)
		(end 362.232194 7.9248)
		(width 0.14732)
		(layer "In4.Cu")
		(net "DELTA_L_85_5INCH_IN2_DN")
	)
	(segment
		(start 355.672136 7.653274)
		(end 355.791516 7.482586)
		(width 0.14732)
		(layer "In4.Cu")
		(net "DELTA_L_85_5INCH_IN2_DN")
	)
	(segment
		(start 358.962198 1.253998)
		(end 360.544618 0.975106)
		(width 0.14732)
		(layer "In4.Cu")
		(net "DELTA_L_85_5INCH_IN2_DN")
	)
	(segment
		(start 373.81942 5.326634)
		(end 376.29846 5.326634)
		(width 0.14732)
		(layer "In4.Cu")
		(net "DELTA_L_85_5INCH_IN2_DN")
	)
	(segment
		(start 347.871542 7.4422)
		(end 346.850208 1.650746)
		(width 0.14732)
		(layer "In4.Cu")
		(net "DELTA_L_85_5INCH_IN2_DN")
	)
	(segment
		(start 358.712516 1.610614)
		(end 358.962198 1.253998)
		(width 0.14732)
		(layer "In4.Cu")
		(net "DELTA_L_85_5INCH_IN2_DN")
	)
	(segment
		(start 366.18037 7.876794)
		(end 367.538762 7.637272)
		(width 0.14732)
		(layer "In4.Cu")
		(net "DELTA_L_85_5INCH_IN2_DN")
	)
	(segment
		(start 364.510574 1.028192)
		(end 364.866936 1.277874)
		(width 0.14732)
		(layer "In4.Cu")
		(net "DELTA_L_85_5INCH_IN2_DN")
	)
	(segment
		(start 362.232194 7.9248)
		(end 363.590586 7.685278)
		(width 0.14732)
		(layer "In4.Cu")
		(net "DELTA_L_85_5INCH_IN2_DN")
	)
	(segment
		(start 354.313744 7.892796)
		(end 355.672136 7.653274)
		(width 0.14732)
		(layer "In4.Cu")
		(net "DELTA_L_85_5INCH_IN2_DN")
	)
	(segment
		(start 368.811302 1.208278)
		(end 369.96243 7.736332)
		(width 0.14732)
		(layer "In4.Cu")
		(net "DELTA_L_85_5INCH_IN2_DN")
	)
	(segment
		(start 366.622584 1.594358)
		(end 366.872266 1.237488)
		(width 0.14732)
		(layer "In4.Cu")
		(net "DELTA_L_85_5INCH_IN2_DN")
	)
	(segment
		(start 369.96243 7.736332)
		(end 370.133118 7.855712)
		(width 0.14732)
		(layer "In4.Cu")
		(net "DELTA_L_85_5INCH_IN2_DN")
	)
	(segment
		(start 367.538762 7.637272)
		(end 367.658142 7.466584)
		(width 0.14732)
		(layer "In4.Cu")
		(net "DELTA_L_85_5INCH_IN2_DN")
	)
	(segment
		(start 370.585492 1.631188)
		(end 370.835174 1.274572)
		(width 0.14732)
		(layer "In4.Cu")
		(net "DELTA_L_85_5INCH_IN2_DN")
	)
	(segment
		(start 358.103424 7.79526)
		(end 358.274112 7.91464)
		(width 0.14732)
		(layer "In4.Cu")
		(net "DELTA_L_85_5INCH_IN2_DN")
	)
	(segment
		(start 350.360234 7.910576)
		(end 351.718626 7.671054)
		(width 0.14732)
		(layer "In4.Cu")
		(net "DELTA_L_85_5INCH_IN2_DN")
	)
	(segment
		(start 346.223082 7.73303)
		(end 346.393516 7.852664)
		(width 0.14732)
		(layer "In4.Cu")
		(net "DELTA_L_85_5INCH_IN2_DN")
	)
	(segment
		(start 360.544618 0.975106)
		(end 360.901234 1.224788)
		(width 0.14732)
		(layer "In4.Cu")
		(net "DELTA_L_85_5INCH_IN2_DN")
	)
	(segment
		(start 356.596188 1.019048)
		(end 356.95255 1.26873)
		(width 0.14732)
		(layer "In4.Cu")
		(net "DELTA_L_85_5INCH_IN2_DN")
	)
	(segment
		(start 371.61089 7.445502)
		(end 370.585492 1.631188)
		(width 0.14732)
		(layer "In4.Cu")
		(net "DELTA_L_85_5INCH_IN2_DN")
	)
	(segment
		(start 363.709966 7.514336)
		(end 362.678472 1.663954)
		(width 0.14732)
		(layer "In4.Cu")
		(net "DELTA_L_85_5INCH_IN2_DN")
	)
	(segment
		(start 372.774464 1.245108)
		(end 373.424704 4.931918)
		(width 0.14732)
		(layer "In4.Cu")
		(net "DELTA_L_85_5INCH_IN2_DN")
	)
	(segment
		(start 345.041474 5.326634)
		(end 345.9607 6.24586)
		(width 0.14732)
		(layer "In4.Cu")
		(net "DELTA_L_85_5INCH_IN2_DN")
	)
	(segment
		(start 377.274074 0.63373)
		(end 376.5931 0.815594)
		(width 0.13208)
		(layer "F.Cu")
		(net "DELTA_L_85_5INCH_IN1_DP")
	)
	(segment
		(start 340.124034 0.63373)
		(end 340.805008 0.815594)
		(width 0.13208)
		(layer "F.Cu")
		(net "DELTA_L_85_5INCH_IN1_DP")
	)
	(segment
		(start 354.249482 3.102864)
		(end 355.831902 2.823972)
		(width 0.14732)
		(layer "In2.Cu")
		(net "DELTA_L_85_5INCH_IN1_DP")
	)
	(segment
		(start 370.87556 -3.38455)
		(end 370.99494 -3.55473)
		(width 0.14732)
		(layer "In2.Cu")
		(net "DELTA_L_85_5INCH_IN1_DP")
	)
	(segment
		(start 368.560604 -3.711956)
		(end 369.711732 2.816098)
		(width 0.14732)
		(layer "In2.Cu")
		(net "DELTA_L_85_5INCH_IN1_DP")
	)
	(segment
		(start 347.911674 2.78384)
		(end 348.16161 2.426462)
		(width 0.14732)
		(layer "In2.Cu")
		(net "DELTA_L_85_5INCH_IN1_DP")
	)
	(segment
		(start 357.852726 2.875026)
		(end 358.20985 3.124708)
		(width 0.14732)
		(layer "In2.Cu")
		(net "DELTA_L_85_5INCH_IN1_DP")
	)
	(segment
		(start 373.705628 0.520954)
		(end 376.29846 0.520954)
		(width 0.14732)
		(layer "In2.Cu")
		(net "DELTA_L_85_5INCH_IN1_DP")
	)
	(segment
		(start 363.750352 2.855722)
		(end 364.000034 2.498344)
		(width 0.14732)
		(layer "In2.Cu")
		(net "DELTA_L_85_5INCH_IN1_DP")
	)
	(segment
		(start 364.000034 2.498344)
		(end 362.96854 -3.351784)
		(width 0.14732)
		(layer "In2.Cu")
		(net "DELTA_L_85_5INCH_IN1_DP")
	)
	(segment
		(start 361.811062 2.884678)
		(end 362.167932 3.134868)
		(width 0.14732)
		(layer "In2.Cu")
		(net "DELTA_L_85_5INCH_IN1_DP")
	)
	(segment
		(start 350.295718 3.120644)
		(end 351.878392 2.841752)
		(width 0.14732)
		(layer "In2.Cu")
		(net "DELTA_L_85_5INCH_IN1_DP")
	)
	(segment
		(start 359.002584 -3.405124)
		(end 359.121964 -3.575304)
		(width 0.14732)
		(layer "In2.Cu")
		(net "DELTA_L_85_5INCH_IN1_DP")
	)
	(segment
		(start 372.353332 -3.794506)
		(end 372.523766 -3.675126)
		(width 0.14732)
		(layer "In2.Cu")
		(net "DELTA_L_85_5INCH_IN1_DP")
	)
	(segment
		(start 370.99494 -3.55473)
		(end 372.353332 -3.794506)
		(width 0.14732)
		(layer "In2.Cu")
		(net "DELTA_L_85_5INCH_IN1_DP")
	)
	(segment
		(start 364.446312 -3.76174)
		(end 364.616492 -3.642614)
		(width 0.14732)
		(layer "In2.Cu")
		(net "DELTA_L_85_5INCH_IN1_DP")
	)
	(segment
		(start 355.831902 2.823972)
		(end 356.081584 2.466848)
		(width 0.14732)
		(layer "In2.Cu")
		(net "DELTA_L_85_5INCH_IN1_DP")
	)
	(segment
		(start 349.939102 2.870454)
		(end 350.295718 3.120644)
		(width 0.14732)
		(layer "In2.Cu")
		(net "DELTA_L_85_5INCH_IN1_DP")
	)
	(segment
		(start 348.618048 -3.774694)
		(end 348.788228 -3.655314)
		(width 0.14732)
		(layer "In2.Cu")
		(net "DELTA_L_85_5INCH_IN1_DP")
	)
	(segment
		(start 340.805008 0.815594)
		(end 341.099648 0.520954)
		(width 0.14732)
		(layer "In2.Cu")
		(net "DELTA_L_85_5INCH_IN1_DP")
	)
	(segment
		(start 344.927682 0.520954)
		(end 345.70543 1.298702)
		(width 0.14732)
		(layer "In2.Cu")
		(net "DELTA_L_85_5INCH_IN1_DP")
	)
	(segment
		(start 362.96854 -3.351784)
		(end 363.08792 -3.522218)
		(width 0.14732)
		(layer "In2.Cu")
		(net "DELTA_L_85_5INCH_IN1_DP")
	)
	(segment
		(start 356.531926 -3.770884)
		(end 356.702106 -3.651758)
		(width 0.14732)
		(layer "In2.Cu")
		(net "DELTA_L_85_5INCH_IN1_DP")
	)
	(segment
		(start 364.616492 -3.642614)
		(end 365.759238 2.836672)
		(width 0.14732)
		(layer "In2.Cu")
		(net "DELTA_L_85_5INCH_IN1_DP")
	)
	(segment
		(start 345.972384 2.812542)
		(end 346.329 3.062732)
		(width 0.14732)
		(layer "In2.Cu")
		(net "DELTA_L_85_5INCH_IN1_DP")
	)
	(segment
		(start 346.329 3.062732)
		(end 347.911674 2.78384)
		(width 0.14732)
		(layer "In2.Cu")
		(net "DELTA_L_85_5INCH_IN1_DP")
	)
	(segment
		(start 352.742246 -3.669538)
		(end 353.892358 2.853182)
		(width 0.14732)
		(layer "In2.Cu")
		(net "DELTA_L_85_5INCH_IN1_DP")
	)
	(segment
		(start 358.20985 3.124708)
		(end 359.792016 2.845816)
		(width 0.14732)
		(layer "In2.Cu")
		(net "DELTA_L_85_5INCH_IN1_DP")
	)
	(segment
		(start 373.169434 -0.01524)
		(end 373.705628 0.520954)
		(width 0.14732)
		(layer "In2.Cu")
		(net "DELTA_L_85_5INCH_IN1_DP")
	)
	(segment
		(start 360.480356 -3.814826)
		(end 360.650536 -3.695446)
		(width 0.14732)
		(layer "In2.Cu")
		(net "DELTA_L_85_5INCH_IN1_DP")
	)
	(segment
		(start 363.08792 -3.522218)
		(end 364.446312 -3.76174)
		(width 0.14732)
		(layer "In2.Cu")
		(net "DELTA_L_85_5INCH_IN1_DP")
	)
	(segment
		(start 367.698528 2.80797)
		(end 367.94821 2.450846)
		(width 0.14732)
		(layer "In2.Cu")
		(net "DELTA_L_85_5INCH_IN1_DP")
	)
	(segment
		(start 347.259656 -3.535426)
		(end 348.618048 -3.774694)
		(width 0.14732)
		(layer "In2.Cu")
		(net "DELTA_L_85_5INCH_IN1_DP")
	)
	(segment
		(start 341.099648 0.520954)
		(end 344.927682 0.520954)
		(width 0.14732)
		(layer "In2.Cu")
		(net "DELTA_L_85_5INCH_IN1_DP")
	)
	(segment
		(start 352.572066 -3.788918)
		(end 352.742246 -3.669538)
		(width 0.14732)
		(layer "In2.Cu")
		(net "DELTA_L_85_5INCH_IN1_DP")
	)
	(segment
		(start 355.054154 -3.36042)
		(end 355.173534 -3.531362)
		(width 0.14732)
		(layer "In2.Cu")
		(net "DELTA_L_85_5INCH_IN1_DP")
	)
	(segment
		(start 352.128328 2.484374)
		(end 351.094294 -3.378708)
		(width 0.14732)
		(layer "In2.Cu")
		(net "DELTA_L_85_5INCH_IN1_DP")
	)
	(segment
		(start 362.167932 3.134868)
		(end 363.750352 2.855722)
		(width 0.14732)
		(layer "In2.Cu")
		(net "DELTA_L_85_5INCH_IN1_DP")
	)
	(segment
		(start 367.032032 -3.591814)
		(end 368.390424 -3.831336)
		(width 0.14732)
		(layer "In2.Cu")
		(net "DELTA_L_85_5INCH_IN1_DP")
	)
	(segment
		(start 370.068856 3.06578)
		(end 370.180616 3.046222)
		(width 0.14732)
		(layer "In2.Cu")
		(net "DELTA_L_85_5INCH_IN1_DP")
	)
	(segment
		(start 372.523766 -3.675126)
		(end 373.169434 -0.01524)
		(width 0.14732)
		(layer "In2.Cu")
		(net "DELTA_L_85_5INCH_IN1_DP")
	)
	(segment
		(start 367.94821 2.450846)
		(end 366.912652 -3.42138)
		(width 0.14732)
		(layer "In2.Cu")
		(net "DELTA_L_85_5INCH_IN1_DP")
	)
	(segment
		(start 353.892358 2.853182)
		(end 354.249482 3.102864)
		(width 0.14732)
		(layer "In2.Cu")
		(net "DELTA_L_85_5INCH_IN1_DP")
	)
	(segment
		(start 345.70543 1.298702)
		(end 345.972384 2.812542)
		(width 0.14732)
		(layer "In2.Cu")
		(net "DELTA_L_85_5INCH_IN1_DP")
	)
	(segment
		(start 371.651276 2.786888)
		(end 371.900958 2.429764)
		(width 0.14732)
		(layer "In2.Cu")
		(net "DELTA_L_85_5INCH_IN1_DP")
	)
	(segment
		(start 356.081584 2.466848)
		(end 355.054154 -3.36042)
		(width 0.14732)
		(layer "In2.Cu")
		(net "DELTA_L_85_5INCH_IN1_DP")
	)
	(segment
		(start 366.912652 -3.42138)
		(end 367.032032 -3.591814)
		(width 0.14732)
		(layer "In2.Cu")
		(net "DELTA_L_85_5INCH_IN1_DP")
	)
	(segment
		(start 348.16161 2.426462)
		(end 347.140276 -3.364992)
		(width 0.14732)
		(layer "In2.Cu")
		(net "DELTA_L_85_5INCH_IN1_DP")
	)
	(segment
		(start 347.140276 -3.364992)
		(end 347.259656 -3.535426)
		(width 0.14732)
		(layer "In2.Cu")
		(net "DELTA_L_85_5INCH_IN1_DP")
	)
	(segment
		(start 348.788228 -3.655314)
		(end 349.939102 2.870454)
		(width 0.14732)
		(layer "In2.Cu")
		(net "DELTA_L_85_5INCH_IN1_DP")
	)
	(segment
		(start 369.711732 2.816098)
		(end 370.068856 3.06578)
		(width 0.14732)
		(layer "In2.Cu")
		(net "DELTA_L_85_5INCH_IN1_DP")
	)
	(segment
		(start 371.900958 2.429764)
		(end 370.87556 -3.38455)
		(width 0.14732)
		(layer "In2.Cu")
		(net "DELTA_L_85_5INCH_IN1_DP")
	)
	(segment
		(start 351.213674 -3.549396)
		(end 352.572066 -3.788918)
		(width 0.14732)
		(layer "In2.Cu")
		(net "DELTA_L_85_5INCH_IN1_DP")
	)
	(segment
		(start 360.650536 -3.695446)
		(end 361.811062 2.884678)
		(width 0.14732)
		(layer "In2.Cu")
		(net "DELTA_L_85_5INCH_IN1_DP")
	)
	(segment
		(start 370.180616 3.046222)
		(end 370.180616 3.045968)
		(width 0.14732)
		(layer "In2.Cu")
		(net "DELTA_L_85_5INCH_IN1_DP")
	)
	(segment
		(start 351.094294 -3.378708)
		(end 351.213674 -3.549396)
		(width 0.14732)
		(layer "In2.Cu")
		(net "DELTA_L_85_5INCH_IN1_DP")
	)
	(segment
		(start 359.121964 -3.575304)
		(end 360.480356 -3.814826)
		(width 0.14732)
		(layer "In2.Cu")
		(net "DELTA_L_85_5INCH_IN1_DP")
	)
	(segment
		(start 360.041952 2.488946)
		(end 359.002584 -3.405124)
		(width 0.14732)
		(layer "In2.Cu")
		(net "DELTA_L_85_5INCH_IN1_DP")
	)
	(segment
		(start 359.792016 2.845816)
		(end 360.041952 2.488946)
		(width 0.14732)
		(layer "In2.Cu")
		(net "DELTA_L_85_5INCH_IN1_DP")
	)
	(segment
		(start 370.180616 3.045968)
		(end 371.651276 2.786888)
		(width 0.14732)
		(layer "In2.Cu")
		(net "DELTA_L_85_5INCH_IN1_DP")
	)
	(segment
		(start 376.29846 0.520954)
		(end 376.5931 0.815594)
		(width 0.14732)
		(layer "In2.Cu")
		(net "DELTA_L_85_5INCH_IN1_DP")
	)
	(segment
		(start 366.116108 3.086862)
		(end 367.698528 2.80797)
		(width 0.14732)
		(layer "In2.Cu")
		(net "DELTA_L_85_5INCH_IN1_DP")
	)
	(segment
		(start 356.702106 -3.651758)
		(end 357.852726 2.875026)
		(width 0.14732)
		(layer "In2.Cu")
		(net "DELTA_L_85_5INCH_IN1_DP")
	)
	(segment
		(start 368.390424 -3.831336)
		(end 368.560604 -3.711956)
		(width 0.14732)
		(layer "In2.Cu")
		(net "DELTA_L_85_5INCH_IN1_DP")
	)
	(segment
		(start 365.759238 2.836672)
		(end 366.116108 3.086862)
		(width 0.14732)
		(layer "In2.Cu")
		(net "DELTA_L_85_5INCH_IN1_DP")
	)
	(segment
		(start 351.878392 2.841752)
		(end 352.128328 2.484374)
		(width 0.14732)
		(layer "In2.Cu")
		(net "DELTA_L_85_5INCH_IN1_DP")
	)
	(segment
		(start 355.173534 -3.531362)
		(end 356.531926 -3.770884)
		(width 0.14732)
		(layer "In2.Cu")
		(net "DELTA_L_85_5INCH_IN1_DP")
	)
	(segment
		(start 340.124034 0.133858)
		(end 340.805008 -0.048006)
		(width 0.13208)
		(layer "F.Cu")
		(net "DELTA_L_85_5INCH_IN1_DN")
	)
	(segment
		(start 377.274074 0.133858)
		(end 376.5931 -0.048006)
		(width 0.13208)
		(layer "F.Cu")
		(net "DELTA_L_85_5INCH_IN1_DN")
	)
	(segment
		(start 363.709966 2.434336)
		(end 362.678472 -3.416046)
		(width 0.14732)
		(layer "In2.Cu")
		(net "DELTA_L_85_5INCH_IN1_DN")
	)
	(segment
		(start 362.928154 -3.772916)
		(end 364.510574 -4.051808)
		(width 0.14732)
		(layer "In2.Cu")
		(net "DELTA_L_85_5INCH_IN1_DN")
	)
	(segment
		(start 356.596188 -4.060952)
		(end 356.95255 -3.81127)
		(width 0.14732)
		(layer "In2.Cu")
		(net "DELTA_L_85_5INCH_IN1_DN")
	)
	(segment
		(start 358.274112 2.83464)
		(end 359.632504 2.595118)
		(width 0.14732)
		(layer "In2.Cu")
		(net "DELTA_L_85_5INCH_IN1_DN")
	)
	(segment
		(start 362.061506 2.725166)
		(end 362.232194 2.8448)
		(width 0.14732)
		(layer "In2.Cu")
		(net "DELTA_L_85_5INCH_IN1_DN")
	)
	(segment
		(start 356.95255 -3.81127)
		(end 358.103424 2.71526)
		(width 0.14732)
		(layer "In2.Cu")
		(net "DELTA_L_85_5INCH_IN1_DN")
	)
	(segment
		(start 370.585492 -3.448812)
		(end 370.835174 -3.805428)
		(width 0.14732)
		(layer "In2.Cu")
		(net "DELTA_L_85_5INCH_IN1_DN")
	)
	(segment
		(start 359.751884 2.424684)
		(end 358.712516 -3.469386)
		(width 0.14732)
		(layer "In2.Cu")
		(net "DELTA_L_85_5INCH_IN1_DN")
	)
	(segment
		(start 354.313744 2.812796)
		(end 355.672136 2.573274)
		(width 0.14732)
		(layer "In2.Cu")
		(net "DELTA_L_85_5INCH_IN1_DN")
	)
	(segment
		(start 347.871542 2.3622)
		(end 346.850208 -3.429254)
		(width 0.14732)
		(layer "In2.Cu")
		(net "DELTA_L_85_5INCH_IN1_DN")
	)
	(segment
		(start 372.417594 -4.084574)
		(end 372.774464 -3.834892)
		(width 0.14732)
		(layer "In2.Cu")
		(net "DELTA_L_85_5INCH_IN1_DN")
	)
	(segment
		(start 348.68231 -4.064762)
		(end 349.038926 -3.81508)
		(width 0.14732)
		(layer "In2.Cu")
		(net "DELTA_L_85_5INCH_IN1_DN")
	)
	(segment
		(start 367.658142 2.386584)
		(end 366.622584 -3.485642)
		(width 0.14732)
		(layer "In2.Cu")
		(net "DELTA_L_85_5INCH_IN1_DN")
	)
	(segment
		(start 373.81942 0.246634)
		(end 376.29846 0.246634)
		(width 0.14732)
		(layer "In2.Cu")
		(net "DELTA_L_85_5INCH_IN1_DN")
	)
	(segment
		(start 354.764086 -3.424682)
		(end 355.013768 -3.781806)
		(width 0.14732)
		(layer "In2.Cu")
		(net "DELTA_L_85_5INCH_IN1_DN")
	)
	(segment
		(start 368.811302 -3.871722)
		(end 369.96243 2.656332)
		(width 0.14732)
		(layer "In2.Cu")
		(net "DELTA_L_85_5INCH_IN1_DN")
	)
	(segment
		(start 366.18037 2.796794)
		(end 367.538762 2.557272)
		(width 0.14732)
		(layer "In2.Cu")
		(net "DELTA_L_85_5INCH_IN1_DN")
	)
	(segment
		(start 346.223082 2.65303)
		(end 346.393516 2.772664)
		(width 0.14732)
		(layer "In2.Cu")
		(net "DELTA_L_85_5INCH_IN1_DN")
	)
	(segment
		(start 358.712516 -3.469386)
		(end 358.962198 -3.826002)
		(width 0.14732)
		(layer "In2.Cu")
		(net "DELTA_L_85_5INCH_IN1_DN")
	)
	(segment
		(start 366.622584 -3.485642)
		(end 366.872266 -3.842512)
		(width 0.14732)
		(layer "In2.Cu")
		(net "DELTA_L_85_5INCH_IN1_DN")
	)
	(segment
		(start 355.672136 2.573274)
		(end 355.791516 2.402586)
		(width 0.14732)
		(layer "In2.Cu")
		(net "DELTA_L_85_5INCH_IN1_DN")
	)
	(segment
		(start 370.133118 2.775712)
		(end 371.49151 2.53619)
		(width 0.14732)
		(layer "In2.Cu")
		(net "DELTA_L_85_5INCH_IN1_DN")
	)
	(segment
		(start 346.393516 2.772664)
		(end 347.751908 2.533142)
		(width 0.14732)
		(layer "In2.Cu")
		(net "DELTA_L_85_5INCH_IN1_DN")
	)
	(segment
		(start 352.992944 -3.829304)
		(end 354.143056 2.693416)
		(width 0.14732)
		(layer "In2.Cu")
		(net "DELTA_L_85_5INCH_IN1_DN")
	)
	(segment
		(start 345.9607 1.16586)
		(end 346.223082 2.65303)
		(width 0.14732)
		(layer "In2.Cu")
		(net "DELTA_L_85_5INCH_IN1_DN")
	)
	(segment
		(start 358.103424 2.71526)
		(end 358.274112 2.83464)
		(width 0.14732)
		(layer "In2.Cu")
		(net "DELTA_L_85_5INCH_IN1_DN")
	)
	(segment
		(start 371.61089 2.365502)
		(end 370.585492 -3.448812)
		(width 0.14732)
		(layer "In2.Cu")
		(net "DELTA_L_85_5INCH_IN1_DN")
	)
	(segment
		(start 345.041474 0.246634)
		(end 345.9607 1.16586)
		(width 0.14732)
		(layer "In2.Cu")
		(net "DELTA_L_85_5INCH_IN1_DN")
	)
	(segment
		(start 347.100144 -3.78587)
		(end 348.68231 -4.064762)
		(width 0.14732)
		(layer "In2.Cu")
		(net "DELTA_L_85_5INCH_IN1_DN")
	)
	(segment
		(start 350.1898 2.710942)
		(end 350.360234 2.830576)
		(width 0.14732)
		(layer "In2.Cu")
		(net "DELTA_L_85_5INCH_IN1_DN")
	)
	(segment
		(start 355.791516 2.402586)
		(end 354.764086 -3.424682)
		(width 0.14732)
		(layer "In2.Cu")
		(net "DELTA_L_85_5INCH_IN1_DN")
	)
	(segment
		(start 351.83826 2.420112)
		(end 350.804226 -3.44297)
		(width 0.14732)
		(layer "In2.Cu")
		(net "DELTA_L_85_5INCH_IN1_DN")
	)
	(segment
		(start 364.510574 -4.051808)
		(end 364.866936 -3.802126)
		(width 0.14732)
		(layer "In2.Cu")
		(net "DELTA_L_85_5INCH_IN1_DN")
	)
	(segment
		(start 371.49151 2.53619)
		(end 371.61089 2.365502)
		(width 0.14732)
		(layer "In2.Cu")
		(net "DELTA_L_85_5INCH_IN1_DN")
	)
	(segment
		(start 341.099648 0.246634)
		(end 345.041474 0.246634)
		(width 0.14732)
		(layer "In2.Cu")
		(net "DELTA_L_85_5INCH_IN1_DN")
	)
	(segment
		(start 360.544618 -4.104894)
		(end 360.901234 -3.855212)
		(width 0.14732)
		(layer "In2.Cu")
		(net "DELTA_L_85_5INCH_IN1_DN")
	)
	(segment
		(start 350.804226 -3.44297)
		(end 351.054162 -3.79984)
		(width 0.14732)
		(layer "In2.Cu")
		(net "DELTA_L_85_5INCH_IN1_DN")
	)
	(segment
		(start 352.636328 -4.078986)
		(end 352.992944 -3.829304)
		(width 0.14732)
		(layer "In2.Cu")
		(net "DELTA_L_85_5INCH_IN1_DN")
	)
	(segment
		(start 351.054162 -3.79984)
		(end 352.636328 -4.078986)
		(width 0.14732)
		(layer "In2.Cu")
		(net "DELTA_L_85_5INCH_IN1_DN")
	)
	(segment
		(start 349.038926 -3.81508)
		(end 350.1898 2.710942)
		(width 0.14732)
		(layer "In2.Cu")
		(net "DELTA_L_85_5INCH_IN1_DN")
	)
	(segment
		(start 340.805008 -0.048006)
		(end 341.099648 0.246634)
		(width 0.14732)
		(layer "In2.Cu")
		(net "DELTA_L_85_5INCH_IN1_DN")
	)
	(segment
		(start 370.835174 -3.805428)
		(end 372.417594 -4.084574)
		(width 0.14732)
		(layer "In2.Cu")
		(net "DELTA_L_85_5INCH_IN1_DN")
	)
	(segment
		(start 369.96243 2.656332)
		(end 370.133118 2.775712)
		(width 0.14732)
		(layer "In2.Cu")
		(net "DELTA_L_85_5INCH_IN1_DN")
	)
	(segment
		(start 351.718626 2.591054)
		(end 351.83826 2.420112)
		(width 0.14732)
		(layer "In2.Cu")
		(net "DELTA_L_85_5INCH_IN1_DN")
	)
	(segment
		(start 362.232194 2.8448)
		(end 363.590586 2.605278)
		(width 0.14732)
		(layer "In2.Cu")
		(net "DELTA_L_85_5INCH_IN1_DN")
	)
	(segment
		(start 363.590586 2.605278)
		(end 363.709966 2.434336)
		(width 0.14732)
		(layer "In2.Cu")
		(net "DELTA_L_85_5INCH_IN1_DN")
	)
	(segment
		(start 359.632504 2.595118)
		(end 359.751884 2.424684)
		(width 0.14732)
		(layer "In2.Cu")
		(net "DELTA_L_85_5INCH_IN1_DN")
	)
	(segment
		(start 367.538762 2.557272)
		(end 367.658142 2.386584)
		(width 0.14732)
		(layer "In2.Cu")
		(net "DELTA_L_85_5INCH_IN1_DN")
	)
	(segment
		(start 347.751908 2.533142)
		(end 347.871542 2.3622)
		(width 0.14732)
		(layer "In2.Cu")
		(net "DELTA_L_85_5INCH_IN1_DN")
	)
	(segment
		(start 358.962198 -3.826002)
		(end 360.544618 -4.104894)
		(width 0.14732)
		(layer "In2.Cu")
		(net "DELTA_L_85_5INCH_IN1_DN")
	)
	(segment
		(start 362.678472 -3.416046)
		(end 362.928154 -3.772916)
		(width 0.14732)
		(layer "In2.Cu")
		(net "DELTA_L_85_5INCH_IN1_DN")
	)
	(segment
		(start 368.454686 -4.121404)
		(end 368.811302 -3.871722)
		(width 0.14732)
		(layer "In2.Cu")
		(net "DELTA_L_85_5INCH_IN1_DN")
	)
	(segment
		(start 350.360234 2.830576)
		(end 351.718626 2.591054)
		(width 0.14732)
		(layer "In2.Cu")
		(net "DELTA_L_85_5INCH_IN1_DN")
	)
	(segment
		(start 346.850208 -3.429254)
		(end 347.100144 -3.78587)
		(width 0.14732)
		(layer "In2.Cu")
		(net "DELTA_L_85_5INCH_IN1_DN")
	)
	(segment
		(start 376.29846 0.246634)
		(end 376.5931 -0.048006)
		(width 0.14732)
		(layer "In2.Cu")
		(net "DELTA_L_85_5INCH_IN1_DN")
	)
	(segment
		(start 360.901234 -3.855212)
		(end 362.061506 2.725166)
		(width 0.14732)
		(layer "In2.Cu")
		(net "DELTA_L_85_5INCH_IN1_DN")
	)
	(segment
		(start 366.009682 2.67716)
		(end 366.18037 2.796794)
		(width 0.14732)
		(layer "In2.Cu")
		(net "DELTA_L_85_5INCH_IN1_DN")
	)
	(segment
		(start 366.872266 -3.842512)
		(end 368.454686 -4.121404)
		(width 0.14732)
		(layer "In2.Cu")
		(net "DELTA_L_85_5INCH_IN1_DN")
	)
	(segment
		(start 373.424704 -0.148082)
		(end 373.81942 0.246634)
		(width 0.14732)
		(layer "In2.Cu")
		(net "DELTA_L_85_5INCH_IN1_DN")
	)
	(segment
		(start 372.774464 -3.834892)
		(end 373.424704 -0.148082)
		(width 0.14732)
		(layer "In2.Cu")
		(net "DELTA_L_85_5INCH_IN1_DN")
	)
	(segment
		(start 364.866936 -3.802126)
		(end 366.009682 2.67716)
		(width 0.14732)
		(layer "In2.Cu")
		(net "DELTA_L_85_5INCH_IN1_DN")
	)
	(segment
		(start 354.143056 2.693416)
		(end 354.313744 2.812796)
		(width 0.14732)
		(layer "In2.Cu")
		(net "DELTA_L_85_5INCH_IN1_DN")
	)
	(segment
		(start 355.013768 -3.781806)
		(end 356.596188 -4.060952)
		(width 0.14732)
		(layer "In2.Cu")
		(net "DELTA_L_85_5INCH_IN1_DN")
	)
	(segment
		(start 347.368876 -5.8166)
		(end 348.803722 -6.069584)
		(width 0.13208)
		(layer "B.Cu")
		(net "DELTA_L_85_5INCH_BOT_DP")
	)
	(segment
		(start 345.237054 -5.954776)
		(end 345.567508 -5.723382)
		(width 0.13208)
		(layer "B.Cu")
		(net "DELTA_L_85_5INCH_BOT_DP")
	)
	(segment
		(start 355.25837 -0.103632)
		(end 354.302568 -5.524246)
		(width 0.13208)
		(layer "B.Cu")
		(net "DELTA_L_85_5INCH_BOT_DP")
	)
	(segment
		(start 368.264694 0.24511)
		(end 369.487704 0.029464)
		(width 0.13208)
		(layer "B.Cu")
		(net "DELTA_L_85_5INCH_BOT_DP")
	)
	(segment
		(start 365.292386 -5.797296)
		(end 366.736884 -6.051804)
		(width 0.13208)
		(layer "B.Cu")
		(net "DELTA_L_85_5INCH_BOT_DP")
	)
	(segment
		(start 371.68455 -2.285746)
		(end 377.037346 -2.285746)
		(width 0.13208)
		(layer "B.Cu")
		(net "DELTA_L_85_5INCH_BOT_DP")
	)
	(segment
		(start 351.562924 0.032766)
		(end 351.670366 -0.120396)
		(width 0.13208)
		(layer "B.Cu")
		(net "DELTA_L_85_5INCH_BOT_DP")
	)
	(segment
		(start 348.089728 -0.093726)
		(end 347.138752 -5.48767)
		(width 0.13208)
		(layer "B.Cu")
		(net "DELTA_L_85_5INCH_BOT_DP")
	)
	(segment
		(start 349.132144 -5.83946)
		(end 350.187006 0.141478)
		(width 0.13208)
		(layer "B.Cu")
		(net "DELTA_L_85_5INCH_BOT_DP")
	)
	(segment
		(start 361.11434 0.356616)
		(end 362.337604 0.14097)
		(width 0.13208)
		(layer "B.Cu")
		(net "DELTA_L_85_5INCH_BOT_DP")
	)
	(segment
		(start 358.735376 0.04445)
		(end 358.842564 -0.108712)
		(width 0.13208)
		(layer "B.Cu")
		(net "DELTA_L_85_5INCH_BOT_DP")
	)
	(segment
		(start 365.90732 0.056134)
		(end 366.014508 -0.096774)
		(width 0.13208)
		(layer "B.Cu")
		(net "DELTA_L_85_5INCH_BOT_DP")
	)
	(segment
		(start 365.066326 -5.474208)
		(end 365.292386 -5.797296)
		(width 0.13208)
		(layer "B.Cu")
		(net "DELTA_L_85_5INCH_BOT_DP")
	)
	(segment
		(start 366.014508 -0.096774)
		(end 365.066326 -5.474208)
		(width 0.13208)
		(layer "B.Cu")
		(net "DELTA_L_85_5INCH_BOT_DP")
	)
	(segment
		(start 351.670366 -0.120396)
		(end 350.719136 -5.51434)
		(width 0.13208)
		(layer "B.Cu")
		(net "DELTA_L_85_5INCH_BOT_DP")
	)
	(segment
		(start 343.801954 -5.701792)
		(end 345.237054 -5.954776)
		(width 0.13208)
		(layer "B.Cu")
		(net "DELTA_L_85_5INCH_BOT_DP")
	)
	(segment
		(start 346.75953 0.275082)
		(end 347.98254 0.059436)
		(width 0.13208)
		(layer "B.Cu")
		(net "DELTA_L_85_5INCH_BOT_DP")
	)
	(segment
		(start 370.630958 -5.90804)
		(end 371.180614 -2.789682)
		(width 0.13208)
		(layer "B.Cu")
		(net "DELTA_L_85_5INCH_BOT_DP")
	)
	(segment
		(start 357.512112 0.260096)
		(end 358.735376 0.04445)
		(width 0.13208)
		(layer "B.Cu")
		(net "DELTA_L_85_5INCH_BOT_DP")
	)
	(segment
		(start 359.880408 -5.880862)
		(end 360.961178 0.249428)
		(width 0.13208)
		(layer "B.Cu")
		(net "DELTA_L_85_5INCH_BOT_DP")
	)
	(segment
		(start 353.927918 0.264922)
		(end 355.151182 0.049276)
		(width 0.13208)
		(layer "B.Cu")
		(net "DELTA_L_85_5INCH_BOT_DP")
	)
	(segment
		(start 343.55405 -2.285746)
		(end 344.033602 -2.76479)
		(width 0.13208)
		(layer "B.Cu")
		(net "DELTA_L_85_5INCH_BOT_DP")
	)
	(segment
		(start 344.033602 -2.76479)
		(end 343.57183 -5.373116)
		(width 0.13208)
		(layer "B.Cu")
		(net "DELTA_L_85_5INCH_BOT_DP")
	)
	(segment
		(start 364.68431 0.272034)
		(end 365.90732 0.056134)
		(width 0.13208)
		(layer "B.Cu")
		(net "DELTA_L_85_5INCH_BOT_DP")
	)
	(segment
		(start 360.961178 0.249428)
		(end 361.11434 0.356616)
		(width 0.13208)
		(layer "B.Cu")
		(net "DELTA_L_85_5INCH_BOT_DP")
	)
	(segment
		(start 361.466892 -5.555996)
		(end 361.692952 -5.879084)
		(width 0.13208)
		(layer "B.Cu")
		(net "DELTA_L_85_5INCH_BOT_DP")
	)
	(segment
		(start 340.355174 -2.285746)
		(end 343.55405 -2.285746)
		(width 0.13208)
		(layer "B.Cu")
		(net "DELTA_L_85_5INCH_BOT_DP")
	)
	(segment
		(start 359.55732 -6.106922)
		(end 359.880408 -5.880862)
		(width 0.13208)
		(layer "B.Cu")
		(net "DELTA_L_85_5INCH_BOT_DP")
	)
	(segment
		(start 350.719136 -5.51434)
		(end 350.94926 -5.843016)
		(width 0.13208)
		(layer "B.Cu")
		(net "DELTA_L_85_5INCH_BOT_DP")
	)
	(segment
		(start 364.531148 0.164846)
		(end 364.68431 0.272034)
		(width 0.13208)
		(layer "B.Cu")
		(net "DELTA_L_85_5INCH_BOT_DP")
	)
	(segment
		(start 368.969036 -5.898388)
		(end 370.308124 -6.134608)
		(width 0.13208)
		(layer "B.Cu")
		(net "DELTA_L_85_5INCH_BOT_DP")
	)
	(segment
		(start 355.151182 0.049276)
		(end 355.25837 -0.103632)
		(width 0.13208)
		(layer "B.Cu")
		(net "DELTA_L_85_5INCH_BOT_DP")
	)
	(segment
		(start 350.33966 0.248412)
		(end 351.562924 0.032766)
		(width 0.13208)
		(layer "B.Cu")
		(net "DELTA_L_85_5INCH_BOT_DP")
	)
	(segment
		(start 354.528628 -5.847334)
		(end 355.973126 -6.101842)
		(width 0.13208)
		(layer "B.Cu")
		(net "DELTA_L_85_5INCH_BOT_DP")
	)
	(segment
		(start 348.803722 -6.069584)
		(end 349.132144 -5.83946)
		(width 0.13208)
		(layer "B.Cu")
		(net "DELTA_L_85_5INCH_BOT_DP")
	)
	(segment
		(start 340.124034 -2.406142)
		(end 340.234778 -2.406142)
		(width 0.13208)
		(layer "B.Cu")
		(net "DELTA_L_85_5INCH_BOT_DP")
	)
	(segment
		(start 369.487704 0.029464)
		(end 369.594892 -0.123698)
		(width 0.13208)
		(layer "B.Cu")
		(net "DELTA_L_85_5INCH_BOT_DP")
	)
	(segment
		(start 354.302568 -5.524246)
		(end 354.528628 -5.847334)
		(width 0.13208)
		(layer "B.Cu")
		(net "DELTA_L_85_5INCH_BOT_DP")
	)
	(segment
		(start 340.234778 -2.406142)
		(end 340.355174 -2.285746)
		(width 0.13208)
		(layer "B.Cu")
		(net "DELTA_L_85_5INCH_BOT_DP")
	)
	(segment
		(start 355.973126 -6.101842)
		(end 356.296214 -5.875782)
		(width 0.13208)
		(layer "B.Cu")
		(net "DELTA_L_85_5INCH_BOT_DP")
	)
	(segment
		(start 371.180614 -2.789682)
		(end 371.68455 -2.285746)
		(width 0.13208)
		(layer "B.Cu")
		(net "DELTA_L_85_5INCH_BOT_DP")
	)
	(segment
		(start 368.637058 -5.556758)
		(end 368.863118 -5.879846)
		(width 0.13208)
		(layer "B.Cu")
		(net "DELTA_L_85_5INCH_BOT_DP")
	)
	(segment
		(start 345.567508 -5.723382)
		(end 346.606368 0.167894)
		(width 0.13208)
		(layer "B.Cu")
		(net "DELTA_L_85_5INCH_BOT_DP")
	)
	(segment
		(start 347.138752 -5.48767)
		(end 347.368876 -5.8166)
		(width 0.13208)
		(layer "B.Cu")
		(net "DELTA_L_85_5INCH_BOT_DP")
	)
	(segment
		(start 343.57183 -5.373116)
		(end 343.801954 -5.701792)
		(width 0.13208)
		(layer "B.Cu")
		(net "DELTA_L_85_5INCH_BOT_DP")
	)
	(segment
		(start 356.296214 -5.875782)
		(end 357.359204 0.152908)
		(width 0.13208)
		(layer "B.Cu")
		(net "DELTA_L_85_5INCH_BOT_DP")
	)
	(segment
		(start 362.444538 -0.011684)
		(end 361.466892 -5.555996)
		(width 0.13208)
		(layer "B.Cu")
		(net "DELTA_L_85_5INCH_BOT_DP")
	)
	(segment
		(start 358.842564 -0.108712)
		(end 357.886762 -5.529326)
		(width 0.13208)
		(layer "B.Cu")
		(net "DELTA_L_85_5INCH_BOT_DP")
	)
	(segment
		(start 347.98254 0.059436)
		(end 348.089728 -0.093726)
		(width 0.13208)
		(layer "B.Cu")
		(net "DELTA_L_85_5INCH_BOT_DP")
	)
	(segment
		(start 357.886762 -5.529326)
		(end 358.112822 -5.852414)
		(width 0.13208)
		(layer "B.Cu")
		(net "DELTA_L_85_5INCH_BOT_DP")
	)
	(segment
		(start 357.359204 0.152908)
		(end 357.512112 0.260096)
		(width 0.13208)
		(layer "B.Cu")
		(net "DELTA_L_85_5INCH_BOT_DP")
	)
	(segment
		(start 352.712782 -5.865876)
		(end 353.77501 0.157734)
		(width 0.13208)
		(layer "B.Cu")
		(net "DELTA_L_85_5INCH_BOT_DP")
	)
	(segment
		(start 352.384106 -6.096254)
		(end 352.712782 -5.865876)
		(width 0.13208)
		(layer "B.Cu")
		(net "DELTA_L_85_5INCH_BOT_DP")
	)
	(segment
		(start 358.112822 -5.852414)
		(end 359.55732 -6.106922)
		(width 0.13208)
		(layer "B.Cu")
		(net "DELTA_L_85_5INCH_BOT_DP")
	)
	(segment
		(start 363.460538 -5.907532)
		(end 364.531148 0.164846)
		(width 0.13208)
		(layer "B.Cu")
		(net "DELTA_L_85_5INCH_BOT_DP")
	)
	(segment
		(start 361.692952 -5.879084)
		(end 363.13745 -6.133592)
		(width 0.13208)
		(layer "B.Cu")
		(net "DELTA_L_85_5INCH_BOT_DP")
	)
	(segment
		(start 377.037346 -2.285746)
		(end 377.157742 -2.406142)
		(width 0.13208)
		(layer "B.Cu")
		(net "DELTA_L_85_5INCH_BOT_DP")
	)
	(segment
		(start 350.94926 -5.843016)
		(end 352.384106 -6.096254)
		(width 0.13208)
		(layer "B.Cu")
		(net "DELTA_L_85_5INCH_BOT_DP")
	)
	(segment
		(start 346.606368 0.167894)
		(end 346.75953 0.275082)
		(width 0.13208)
		(layer "B.Cu")
		(net "DELTA_L_85_5INCH_BOT_DP")
	)
	(segment
		(start 363.13745 -6.133592)
		(end 363.460538 -5.907532)
		(width 0.13208)
		(layer "B.Cu")
		(net "DELTA_L_85_5INCH_BOT_DP")
	)
	(segment
		(start 353.77501 0.157734)
		(end 353.927918 0.264922)
		(width 0.13208)
		(layer "B.Cu")
		(net "DELTA_L_85_5INCH_BOT_DP")
	)
	(segment
		(start 368.111532 0.137922)
		(end 368.264694 0.24511)
		(width 0.13208)
		(layer "B.Cu")
		(net "DELTA_L_85_5INCH_BOT_DP")
	)
	(segment
		(start 370.308124 -6.134608)
		(end 370.630958 -5.90804)
		(width 0.13208)
		(layer "B.Cu")
		(net "DELTA_L_85_5INCH_BOT_DP")
	)
	(segment
		(start 368.863118 -5.879846)
		(end 368.969036 -5.898642)
		(width 0.13208)
		(layer "B.Cu")
		(net "DELTA_L_85_5INCH_BOT_DP")
	)
	(segment
		(start 368.969036 -5.898642)
		(end 368.969036 -5.898388)
		(width 0.13208)
		(layer "B.Cu")
		(net "DELTA_L_85_5INCH_BOT_DP")
	)
	(segment
		(start 366.736884 -6.051804)
		(end 367.059972 -5.825744)
		(width 0.13208)
		(layer "B.Cu")
		(net "DELTA_L_85_5INCH_BOT_DP")
	)
	(segment
		(start 367.059972 -5.825744)
		(end 368.111532 0.137922)
		(width 0.13208)
		(layer "B.Cu")
		(net "DELTA_L_85_5INCH_BOT_DP")
	)
	(segment
		(start 350.187006 0.141478)
		(end 350.33966 0.248412)
		(width 0.13208)
		(layer "B.Cu")
		(net "DELTA_L_85_5INCH_BOT_DP")
	)
	(segment
		(start 369.594892 -0.123698)
		(end 368.637058 -5.556758)
		(width 0.13208)
		(layer "B.Cu")
		(net "DELTA_L_85_5INCH_BOT_DP")
	)
	(segment
		(start 362.337604 0.14097)
		(end 362.444538 -0.011684)
		(width 0.13208)
		(layer "B.Cu")
		(net "DELTA_L_85_5INCH_BOT_DP")
	)
	(segment
		(start 377.157742 -2.406142)
		(end 377.274074 -2.406142)
		(width 0.13208)
		(layer "B.Cu")
		(net "DELTA_L_85_5INCH_BOT_DP")
	)
	(segment
		(start 361.053634 0.630428)
		(end 362.48848 0.377698)
		(width 0.13208)
		(layer "B.Cu")
		(net "DELTA_L_85_5INCH_BOT_DN")
	)
	(segment
		(start 359.496614 -5.83311)
		(end 359.64368 -5.729986)
		(width 0.13208)
		(layer "B.Cu")
		(net "DELTA_L_85_5INCH_BOT_DN")
	)
	(segment
		(start 352.476054 -5.715254)
		(end 353.538282 0.308356)
		(width 0.13208)
		(layer "B.Cu")
		(net "DELTA_L_85_5INCH_BOT_DN")
	)
	(segment
		(start 371.577108 -2.026666)
		(end 377.042934 -2.026666)
		(width 0.13208)
		(layer "B.Cu")
		(net "DELTA_L_85_5INCH_BOT_DN")
	)
	(segment
		(start 364.623604 0.545846)
		(end 366.058196 0.292862)
		(width 0.13208)
		(layer "B.Cu")
		(net "DELTA_L_85_5INCH_BOT_DN")
	)
	(segment
		(start 366.823244 -5.674868)
		(end 367.875058 0.288798)
		(width 0.13208)
		(layer "B.Cu")
		(net "DELTA_L_85_5INCH_BOT_DN")
	)
	(segment
		(start 361.843828 -5.642356)
		(end 363.076744 -5.85978)
		(width 0.13208)
		(layer "B.Cu")
		(net "DELTA_L_85_5INCH_BOT_DN")
	)
	(segment
		(start 340.124034 -1.90627)
		(end 340.240366 -1.90627)
		(width 0.13208)
		(layer "B.Cu")
		(net "DELTA_L_85_5INCH_BOT_DN")
	)
	(segment
		(start 360.72445 0.400304)
		(end 361.053634 0.630428)
		(width 0.13208)
		(layer "B.Cu")
		(net "DELTA_L_85_5INCH_BOT_DN")
	)
	(segment
		(start 345.33078 -5.572506)
		(end 346.36964 0.31877)
		(width 0.13208)
		(layer "B.Cu")
		(net "DELTA_L_85_5INCH_BOT_DN")
	)
	(segment
		(start 348.133416 0.296164)
		(end 348.36354 -0.03302)
		(width 0.13208)
		(layer "B.Cu")
		(net "DELTA_L_85_5INCH_BOT_DN")
	)
	(segment
		(start 346.36964 0.31877)
		(end 346.698824 0.548894)
		(width 0.13208)
		(layer "B.Cu")
		(net "DELTA_L_85_5INCH_BOT_DN")
	)
	(segment
		(start 343.95283 -5.465064)
		(end 345.176348 -5.680964)
		(width 0.13208)
		(layer "B.Cu")
		(net "DELTA_L_85_5INCH_BOT_DN")
	)
	(segment
		(start 356.059486 -5.724906)
		(end 357.122476 0.30353)
		(width 0.13208)
		(layer "B.Cu")
		(net "DELTA_L_85_5INCH_BOT_DN")
	)
	(segment
		(start 358.160574 -5.46862)
		(end 358.263698 -5.615686)
		(width 0.13208)
		(layer "B.Cu")
		(net "DELTA_L_85_5INCH_BOT_DN")
	)
	(segment
		(start 348.36354 -0.03302)
		(end 347.412564 -5.426964)
		(width 0.13208)
		(layer "B.Cu")
		(net "DELTA_L_85_5INCH_BOT_DN")
	)
	(segment
		(start 366.288574 -0.036068)
		(end 365.340138 -5.413502)
		(width 0.13208)
		(layer "B.Cu")
		(net "DELTA_L_85_5INCH_BOT_DN")
	)
	(segment
		(start 355.301804 0.286004)
		(end 355.532436 -0.042926)
		(width 0.13208)
		(layer "B.Cu")
		(net "DELTA_L_85_5INCH_BOT_DN")
	)
	(segment
		(start 350.278954 0.522224)
		(end 351.713546 0.269494)
		(width 0.13208)
		(layer "B.Cu")
		(net "DELTA_L_85_5INCH_BOT_DN")
	)
	(segment
		(start 368.203988 0.518922)
		(end 369.63858 0.266192)
		(width 0.13208)
		(layer "B.Cu")
		(net "DELTA_L_85_5INCH_BOT_DN")
	)
	(segment
		(start 340.240366 -1.90627)
		(end 340.360762 -2.026666)
		(width 0.13208)
		(layer "B.Cu")
		(net "DELTA_L_85_5INCH_BOT_DN")
	)
	(segment
		(start 370.39423 -5.757418)
		(end 370.939568 -2.664206)
		(width 0.13208)
		(layer "B.Cu")
		(net "DELTA_L_85_5INCH_BOT_DN")
	)
	(segment
		(start 343.661492 -2.026666)
		(end 344.312494 -2.676906)
		(width 0.13208)
		(layer "B.Cu")
		(net "DELTA_L_85_5INCH_BOT_DN")
	)
	(segment
		(start 355.532436 -0.042926)
		(end 354.57638 -5.46354)
		(width 0.13208)
		(layer "B.Cu")
		(net "DELTA_L_85_5INCH_BOT_DN")
	)
	(segment
		(start 354.57638 -5.46354)
		(end 354.679504 -5.610606)
		(width 0.13208)
		(layer "B.Cu")
		(net "DELTA_L_85_5INCH_BOT_DN")
	)
	(segment
		(start 367.875058 0.288798)
		(end 368.203988 0.518922)
		(width 0.13208)
		(layer "B.Cu")
		(net "DELTA_L_85_5INCH_BOT_DN")
	)
	(segment
		(start 357.122476 0.30353)
		(end 357.451152 0.534162)
		(width 0.13208)
		(layer "B.Cu")
		(net "DELTA_L_85_5INCH_BOT_DN")
	)
	(segment
		(start 359.64368 -5.729986)
		(end 360.72445 0.400304)
		(width 0.13208)
		(layer "B.Cu")
		(net "DELTA_L_85_5INCH_BOT_DN")
	)
	(segment
		(start 347.519752 -5.579872)
		(end 348.743016 -5.795518)
		(width 0.13208)
		(layer "B.Cu")
		(net "DELTA_L_85_5INCH_BOT_DN")
	)
	(segment
		(start 358.886252 0.281178)
		(end 359.116376 -0.048006)
		(width 0.13208)
		(layer "B.Cu")
		(net "DELTA_L_85_5INCH_BOT_DN")
	)
	(segment
		(start 366.676178 -5.777992)
		(end 366.823244 -5.674868)
		(width 0.13208)
		(layer "B.Cu")
		(net "DELTA_L_85_5INCH_BOT_DN")
	)
	(segment
		(start 366.058196 0.292862)
		(end 366.288574 -0.036068)
		(width 0.13208)
		(layer "B.Cu")
		(net "DELTA_L_85_5INCH_BOT_DN")
	)
	(segment
		(start 343.845896 -5.31241)
		(end 343.95283 -5.465064)
		(width 0.13208)
		(layer "B.Cu")
		(net "DELTA_L_85_5INCH_BOT_DN")
	)
	(segment
		(start 368.91087 -5.496052)
		(end 369.013994 -5.643118)
		(width 0.13208)
		(layer "B.Cu")
		(net "DELTA_L_85_5INCH_BOT_DN")
	)
	(segment
		(start 353.538282 0.308356)
		(end 353.866958 0.538988)
		(width 0.13208)
		(layer "B.Cu")
		(net "DELTA_L_85_5INCH_BOT_DN")
	)
	(segment
		(start 350.992948 -5.453634)
		(end 351.100136 -5.606288)
		(width 0.13208)
		(layer "B.Cu")
		(net "DELTA_L_85_5INCH_BOT_DN")
	)
	(segment
		(start 351.713546 0.269494)
		(end 351.944432 -0.059436)
		(width 0.13208)
		(layer "B.Cu")
		(net "DELTA_L_85_5INCH_BOT_DN")
	)
	(segment
		(start 370.939568 -2.664206)
		(end 371.577108 -2.026666)
		(width 0.13208)
		(layer "B.Cu")
		(net "DELTA_L_85_5INCH_BOT_DN")
	)
	(segment
		(start 377.16333 -1.90627)
		(end 377.274074 -1.90627)
		(width 0.13208)
		(layer "B.Cu")
		(net "DELTA_L_85_5INCH_BOT_DN")
	)
	(segment
		(start 352.3234 -5.822188)
		(end 352.476054 -5.715254)
		(width 0.13208)
		(layer "B.Cu")
		(net "DELTA_L_85_5INCH_BOT_DN")
	)
	(segment
		(start 357.451152 0.534162)
		(end 358.886252 0.281178)
		(width 0.13208)
		(layer "B.Cu")
		(net "DELTA_L_85_5INCH_BOT_DN")
	)
	(segment
		(start 351.100136 -5.606288)
		(end 352.3234 -5.822188)
		(width 0.13208)
		(layer "B.Cu")
		(net "DELTA_L_85_5INCH_BOT_DN")
	)
	(segment
		(start 346.698824 0.548894)
		(end 348.133416 0.296164)
		(width 0.13208)
		(layer "B.Cu")
		(net "DELTA_L_85_5INCH_BOT_DN")
	)
	(segment
		(start 351.944432 -0.059436)
		(end 350.992948 -5.453634)
		(width 0.13208)
		(layer "B.Cu")
		(net "DELTA_L_85_5INCH_BOT_DN")
	)
	(segment
		(start 369.013994 -5.643118)
		(end 370.247164 -5.860542)
		(width 0.13208)
		(layer "B.Cu")
		(net "DELTA_L_85_5INCH_BOT_DN")
	)
	(segment
		(start 363.22381 -5.756656)
		(end 364.29442 0.315722)
		(width 0.13208)
		(layer "B.Cu")
		(net "DELTA_L_85_5INCH_BOT_DN")
	)
	(segment
		(start 359.116376 -0.048006)
		(end 358.160574 -5.46862)
		(width 0.13208)
		(layer "B.Cu")
		(net "DELTA_L_85_5INCH_BOT_DN")
	)
	(segment
		(start 364.29442 0.315722)
		(end 364.623604 0.545846)
		(width 0.13208)
		(layer "B.Cu")
		(net "DELTA_L_85_5INCH_BOT_DN")
	)
	(segment
		(start 347.412564 -5.426964)
		(end 347.519752 -5.579872)
		(width 0.13208)
		(layer "B.Cu")
		(net "DELTA_L_85_5INCH_BOT_DN")
	)
	(segment
		(start 361.740704 -5.49529)
		(end 361.843828 -5.642356)
		(width 0.13208)
		(layer "B.Cu")
		(net "DELTA_L_85_5INCH_BOT_DN")
	)
	(segment
		(start 377.042934 -2.026666)
		(end 377.16333 -1.90627)
		(width 0.13208)
		(layer "B.Cu")
		(net "DELTA_L_85_5INCH_BOT_DN")
	)
	(segment
		(start 353.866958 0.538988)
		(end 355.301804 0.286004)
		(width 0.13208)
		(layer "B.Cu")
		(net "DELTA_L_85_5INCH_BOT_DN")
	)
	(segment
		(start 362.71835 0.049022)
		(end 361.740704 -5.49529)
		(width 0.13208)
		(layer "B.Cu")
		(net "DELTA_L_85_5INCH_BOT_DN")
	)
	(segment
		(start 348.895416 -5.688584)
		(end 349.950278 0.2921)
		(width 0.13208)
		(layer "B.Cu")
		(net "DELTA_L_85_5INCH_BOT_DN")
	)
	(segment
		(start 340.360762 -2.026666)
		(end 343.661492 -2.026666)
		(width 0.13208)
		(layer "B.Cu")
		(net "DELTA_L_85_5INCH_BOT_DN")
	)
	(segment
		(start 370.247164 -5.860542)
		(end 370.39423 -5.757418)
		(width 0.13208)
		(layer "B.Cu")
		(net "DELTA_L_85_5INCH_BOT_DN")
	)
	(segment
		(start 369.868704 -0.062992)
		(end 368.91087 -5.496052)
		(width 0.13208)
		(layer "B.Cu")
		(net "DELTA_L_85_5INCH_BOT_DN")
	)
	(segment
		(start 355.91242 -5.82803)
		(end 356.059486 -5.724906)
		(width 0.13208)
		(layer "B.Cu")
		(net "DELTA_L_85_5INCH_BOT_DN")
	)
	(segment
		(start 365.443262 -5.560568)
		(end 366.676178 -5.777992)
		(width 0.13208)
		(layer "B.Cu")
		(net "DELTA_L_85_5INCH_BOT_DN")
	)
	(segment
		(start 348.743016 -5.795518)
		(end 348.895416 -5.688584)
		(width 0.13208)
		(layer "B.Cu")
		(net "DELTA_L_85_5INCH_BOT_DN")
	)
	(segment
		(start 362.48848 0.377698)
		(end 362.71835 0.049022)
		(width 0.13208)
		(layer "B.Cu")
		(net "DELTA_L_85_5INCH_BOT_DN")
	)
	(segment
		(start 354.679504 -5.610606)
		(end 355.91242 -5.82803)
		(width 0.13208)
		(layer "B.Cu")
		(net "DELTA_L_85_5INCH_BOT_DN")
	)
	(segment
		(start 358.263698 -5.615686)
		(end 359.496614 -5.83311)
		(width 0.13208)
		(layer "B.Cu")
		(net "DELTA_L_85_5INCH_BOT_DN")
	)
	(segment
		(start 363.076744 -5.85978)
		(end 363.22381 -5.756656)
		(width 0.13208)
		(layer "B.Cu")
		(net "DELTA_L_85_5INCH_BOT_DN")
	)
	(segment
		(start 369.63858 0.266192)
		(end 369.868704 -0.062992)
		(width 0.13208)
		(layer "B.Cu")
		(net "DELTA_L_85_5INCH_BOT_DN")
	)
	(segment
		(start 349.950278 0.2921)
		(end 350.278954 0.522224)
		(width 0.13208)
		(layer "B.Cu")
		(net "DELTA_L_85_5INCH_BOT_DN")
	)
	(segment
		(start 344.312494 -2.676906)
		(end 343.845896 -5.31241)
		(width 0.13208)
		(layer "B.Cu")
		(net "DELTA_L_85_5INCH_BOT_DN")
	)
	(segment
		(start 365.340138 -5.413502)
		(end 365.443262 -5.560568)
		(width 0.13208)
		(layer "B.Cu")
		(net "DELTA_L_85_5INCH_BOT_DN")
	)
	(segment
		(start 345.176348 -5.680964)
		(end 345.33078 -5.572506)
		(width 0.13208)
		(layer "B.Cu")
		(net "DELTA_L_85_5INCH_BOT_DN")
	)
	(segment
		(start 267.87856 -2.336546)
		(end 267.986002 -2.489708)
		(width 0.13208)
		(layer "F.Cu")
		(net "DELTA_L_85_10INCH_TOP_DP")
	)
	(segment
		(start 278.727916 -2.568956)
		(end 277.790148 -7.88543)
		(width 0.13208)
		(layer "F.Cu")
		(net "DELTA_L_85_10INCH_TOP_DP")
	)
	(segment
		(start 291.752528 -2.11836)
		(end 292.975792 -2.334006)
		(width 0.13208)
		(layer "F.Cu")
		(net "DELTA_L_85_10INCH_TOP_DP")
	)
	(segment
		(start 276.210522 -8.168894)
		(end 277.244556 -2.307336)
		(width 0.13208)
		(layer "F.Cu")
		(net "DELTA_L_85_10INCH_TOP_DP")
	)
	(segment
		(start 305.9176 -2.382266)
		(end 306.070508 -2.275078)
		(width 0.13208)
		(layer "F.Cu")
		(net "DELTA_L_85_10INCH_TOP_DP")
	)
	(segment
		(start 309.501794 -2.387092)
		(end 309.654702 -2.279904)
		(width 0.13208)
		(layer "F.Cu")
		(net "DELTA_L_85_10INCH_TOP_DP")
	)
	(segment
		(start 314.480194 -2.39903)
		(end 314.587128 -2.551684)
		(width 0.13208)
		(layer "F.Cu")
		(net "DELTA_L_85_10INCH_TOP_DP")
	)
	(segment
		(start 310.058308 -7.905242)
		(end 310.284368 -8.22833)
		(width 0.13208)
		(layer "F.Cu")
		(net "DELTA_L_85_10INCH_TOP_DP")
	)
	(segment
		(start 310.985154 -2.648712)
		(end 310.058308 -7.905242)
		(width 0.13208)
		(layer "F.Cu")
		(net "DELTA_L_85_10INCH_TOP_DP")
	)
	(segment
		(start 310.284368 -8.22833)
		(end 311.728866 -8.482838)
		(width 0.13208)
		(layer "F.Cu")
		(net "DELTA_L_85_10INCH_TOP_DP")
	)
	(segment
		(start 287.997392 -2.322068)
		(end 288.1503 -2.21488)
		(width 0.13208)
		(layer "F.Cu")
		(net "DELTA_L_85_10INCH_TOP_DP")
	)
	(segment
		(start 284.566106 -2.210054)
		(end 285.78937 -2.4257)
		(width 0.13208)
		(layer "F.Cu")
		(net "DELTA_L_85_10INCH_TOP_DP")
	)
	(segment
		(start 270.625824 -7.849616)
		(end 270.856456 -8.178038)
		(width 0.13208)
		(layer "F.Cu")
		(net "DELTA_L_85_10INCH_TOP_DP")
	)
	(segment
		(start 289.373564 -2.430526)
		(end 289.480752 -2.583688)
		(width 0.13208)
		(layer "F.Cu")
		(net "DELTA_L_85_10INCH_TOP_DP")
	)
	(segment
		(start 306.070508 -2.275078)
		(end 307.293772 -2.490724)
		(width 0.13208)
		(layer "F.Cu")
		(net "DELTA_L_85_10INCH_TOP_DP")
	)
	(segment
		(start 315.636402 -8.25881)
		(end 316.673738 -2.375154)
		(width 0.13208)
		(layer "F.Cu")
		(net "DELTA_L_85_10INCH_TOP_DP")
	)
	(segment
		(start 313.25693 -2.183384)
		(end 314.480194 -2.39903)
		(width 0.13208)
		(layer "F.Cu")
		(net "DELTA_L_85_10INCH_TOP_DP")
	)
	(segment
		(start 328.298556 -4.946142)
		(end 328.414888 -4.946142)
		(width 0.13208)
		(layer "F.Cu")
		(net "DELTA_L_85_10INCH_TOP_DP")
	)
	(segment
		(start 267.266166 -8.20674)
		(end 268.701012 -8.459978)
		(width 0.13208)
		(layer "F.Cu")
		(net "DELTA_L_85_10INCH_TOP_DP")
	)
	(segment
		(start 316.673738 -2.375154)
		(end 316.8269 -2.267966)
		(width 0.13208)
		(layer "F.Cu")
		(net "DELTA_L_85_10INCH_TOP_DP")
	)
	(segment
		(start 295.169336 -2.310638)
		(end 295.322498 -2.202942)
		(width 0.13208)
		(layer "F.Cu")
		(net "DELTA_L_85_10INCH_TOP_DP")
	)
	(segment
		(start 320.254122 -2.402078)
		(end 320.407284 -2.29489)
		(width 0.13208)
		(layer "F.Cu")
		(net "DELTA_L_85_10INCH_TOP_DP")
	)
	(segment
		(start 275.882354 -8.399526)
		(end 276.210522 -8.168894)
		(width 0.13208)
		(layer "F.Cu")
		(net "DELTA_L_85_10INCH_TOP_DP")
	)
	(segment
		(start 298.749974 -2.337054)
		(end 298.902882 -2.229866)
		(width 0.13208)
		(layer "F.Cu")
		(net "DELTA_L_85_10INCH_TOP_DP")
	)
	(segment
		(start 288.767774 -8.234172)
		(end 290.212272 -8.488934)
		(width 0.13208)
		(layer "F.Cu")
		(net "DELTA_L_85_10INCH_TOP_DP")
	)
	(segment
		(start 278.620474 -2.415794)
		(end 278.727916 -2.568956)
		(width 0.13208)
		(layer "F.Cu")
		(net "DELTA_L_85_10INCH_TOP_DP")
	)
	(segment
		(start 289.480752 -2.583688)
		(end 288.541206 -7.911338)
		(width 0.13208)
		(layer "F.Cu")
		(net "DELTA_L_85_10INCH_TOP_DP")
	)
	(segment
		(start 277.244556 -2.307336)
		(end 277.39721 -2.200148)
		(width 0.13208)
		(layer "F.Cu")
		(net "DELTA_L_85_10INCH_TOP_DP")
	)
	(segment
		(start 283.038042 -8.48106)
		(end 283.366718 -8.25119)
		(width 0.13208)
		(layer "F.Cu")
		(net "DELTA_L_85_10INCH_TOP_DP")
	)
	(segment
		(start 271.459198 -2.362962)
		(end 271.56664 -2.516124)
		(width 0.13208)
		(layer "F.Cu")
		(net "DELTA_L_85_10INCH_TOP_DP")
	)
	(segment
		(start 267.986002 -2.489708)
		(end 267.035534 -7.878318)
		(width 0.13208)
		(layer "F.Cu")
		(net "DELTA_L_85_10INCH_TOP_DP")
	)
	(segment
		(start 312.051954 -8.256778)
		(end 313.103768 -2.290572)
		(width 0.13208)
		(layer "F.Cu")
		(net "DELTA_L_85_10INCH_TOP_DP")
	)
	(segment
		(start 261.557008 -4.946142)
		(end 261.667752 -4.946142)
		(width 0.13208)
		(layer "F.Cu")
		(net "DELTA_L_85_10INCH_TOP_DP")
	)
	(segment
		(start 277.790148 -7.88543)
		(end 278.02078 -8.213852)
		(width 0.13208)
		(layer "F.Cu")
		(net "DELTA_L_85_10INCH_TOP_DP")
	)
	(segment
		(start 307.293772 -2.490724)
		(end 307.40096 -2.643632)
		(width 0.13208)
		(layer "F.Cu")
		(net "DELTA_L_85_10INCH_TOP_DP")
	)
	(segment
		(start 295.322498 -2.203196)
		(end 296.545508 -2.418842)
		(width 0.13208)
		(layer "F.Cu")
		(net "DELTA_L_85_10INCH_TOP_DP")
	)
	(segment
		(start 274.447508 -8.146288)
		(end 275.882354 -8.399526)
		(width 0.13208)
		(layer "F.Cu")
		(net "DELTA_L_85_10INCH_TOP_DP")
	)
	(segment
		(start 318.157098 -2.636774)
		(end 317.223394 -7.931912)
		(width 0.13208)
		(layer "F.Cu")
		(net "DELTA_L_85_10INCH_TOP_DP")
	)
	(segment
		(start 320.407284 -2.29489)
		(end 321.630294 -2.510536)
		(width 0.13208)
		(layer "F.Cu")
		(net "DELTA_L_85_10INCH_TOP_DP")
	)
	(segment
		(start 261.776464 -4.83743)
		(end 265.589258 -4.83743)
		(width 0.13208)
		(layer "F.Cu")
		(net "DELTA_L_85_10INCH_TOP_DP")
	)
	(segment
		(start 321.737482 -2.663698)
		(end 320.80581 -7.947406)
		(width 0.13208)
		(layer "F.Cu")
		(net "DELTA_L_85_10INCH_TOP_DP")
	)
	(segment
		(start 315.313314 -8.48487)
		(end 315.636402 -8.25881)
		(width 0.13208)
		(layer "F.Cu")
		(net "DELTA_L_85_10INCH_TOP_DP")
	)
	(segment
		(start 265.589258 -4.83743)
		(end 266.121134 -4.391406)
		(width 0.13208)
		(layer "F.Cu")
		(net "DELTA_L_85_10INCH_TOP_DP")
	)
	(segment
		(start 285.78937 -2.4257)
		(end 285.896558 -2.578862)
		(width 0.13208)
		(layer "F.Cu")
		(net "DELTA_L_85_10INCH_TOP_DP")
	)
	(segment
		(start 313.103768 -2.290572)
		(end 313.25693 -2.183384)
		(width 0.13208)
		(layer "F.Cu")
		(net "DELTA_L_85_10INCH_TOP_DP")
	)
	(segment
		(start 280.977848 -2.226564)
		(end 282.201112 -2.44221)
		(width 0.13208)
		(layer "F.Cu")
		(net "DELTA_L_85_10INCH_TOP_DP")
	)
	(segment
		(start 269.029434 -8.229346)
		(end 270.08328 -2.254504)
		(width 0.13208)
		(layer "F.Cu")
		(net "DELTA_L_85_10INCH_TOP_DP")
	)
	(segment
		(start 328.17816 -4.825746)
		(end 328.298556 -4.946142)
		(width 0.13208)
		(layer "F.Cu")
		(net "DELTA_L_85_10INCH_TOP_DP")
	)
	(segment
		(start 278.02078 -8.213852)
		(end 279.455626 -8.46709)
		(width 0.13208)
		(layer "F.Cu")
		(net "DELTA_L_85_10INCH_TOP_DP")
	)
	(segment
		(start 306.471066 -7.917942)
		(end 306.697126 -8.24103)
		(width 0.13208)
		(layer "F.Cu")
		(net "DELTA_L_85_10INCH_TOP_DP")
	)
	(segment
		(start 293.791132 -8.522716)
		(end 294.113966 -8.296148)
		(width 0.13208)
		(layer "F.Cu")
		(net "DELTA_L_85_10INCH_TOP_DP")
	)
	(segment
		(start 292.346634 -8.267954)
		(end 293.791132 -8.522716)
		(width 0.13208)
		(layer "F.Cu")
		(net "DELTA_L_85_10INCH_TOP_DP")
	)
	(segment
		(start 283.366718 -8.25119)
		(end 284.413198 -2.317242)
		(width 0.13208)
		(layer "F.Cu")
		(net "DELTA_L_85_10INCH_TOP_DP")
	)
	(segment
		(start 273.663918 -2.28092)
		(end 273.816572 -2.173732)
		(width 0.13208)
		(layer "F.Cu")
		(net "DELTA_L_85_10INCH_TOP_DP")
	)
	(segment
		(start 286.950912 -8.257032)
		(end 287.997392 -2.322068)
		(width 0.13208)
		(layer "F.Cu")
		(net "DELTA_L_85_10INCH_TOP_DP")
	)
	(segment
		(start 308.141624 -8.495538)
		(end 308.464458 -8.269478)
		(width 0.13208)
		(layer "F.Cu")
		(net "DELTA_L_85_10INCH_TOP_DP")
	)
	(segment
		(start 292.975792 -2.334006)
		(end 293.082726 -2.48666)
		(width 0.13208)
		(layer "F.Cu")
		(net "DELTA_L_85_10INCH_TOP_DP")
	)
	(segment
		(start 318.04991 -2.483866)
		(end 318.157098 -2.636774)
		(width 0.13208)
		(layer "F.Cu")
		(net "DELTA_L_85_10INCH_TOP_DP")
	)
	(segment
		(start 316.8269 -2.267966)
		(end 318.04991 -2.483866)
		(width 0.13208)
		(layer "F.Cu")
		(net "DELTA_L_85_10INCH_TOP_DP")
	)
	(segment
		(start 322.799964 -8.298434)
		(end 323.323204 -5.329682)
		(width 0.13208)
		(layer "F.Cu")
		(net "DELTA_L_85_10INCH_TOP_DP")
	)
	(segment
		(start 303.119282 -8.227822)
		(end 304.554128 -8.48106)
		(width 0.13208)
		(layer "F.Cu")
		(net "DELTA_L_85_10INCH_TOP_DP")
	)
	(segment
		(start 296.545508 -2.418842)
		(end 296.65295 -2.57175)
		(width 0.13208)
		(layer "F.Cu")
		(net "DELTA_L_85_10INCH_TOP_DP")
	)
	(segment
		(start 314.587128 -2.551684)
		(end 313.642756 -7.907274)
		(width 0.13208)
		(layer "F.Cu")
		(net "DELTA_L_85_10INCH_TOP_DP")
	)
	(segment
		(start 321.032378 -8.27024)
		(end 322.47713 -8.525002)
		(width 0.13208)
		(layer "F.Cu")
		(net "DELTA_L_85_10INCH_TOP_DP")
	)
	(segment
		(start 300.125892 -2.445512)
		(end 300.23308 -2.598674)
		(width 0.13208)
		(layer "F.Cu")
		(net "DELTA_L_85_10INCH_TOP_DP")
	)
	(segment
		(start 323.82714 -4.825746)
		(end 328.17816 -4.825746)
		(width 0.13208)
		(layer "F.Cu")
		(net "DELTA_L_85_10INCH_TOP_DP")
	)
	(segment
		(start 303.812956 -2.660396)
		(end 302.889158 -7.899146)
		(width 0.13208)
		(layer "F.Cu")
		(net "DELTA_L_85_10INCH_TOP_DP")
	)
	(segment
		(start 297.380406 -8.49884)
		(end 297.70324 -8.272272)
		(width 0.13208)
		(layer "F.Cu")
		(net "DELTA_L_85_10INCH_TOP_DP")
	)
	(segment
		(start 272.291302 -8.431276)
		(end 272.619724 -8.200644)
		(width 0.13208)
		(layer "F.Cu")
		(net "DELTA_L_85_10INCH_TOP_DP")
	)
	(segment
		(start 320.80581 -7.947406)
		(end 321.032378 -8.27024)
		(width 0.13208)
		(layer "F.Cu")
		(net "DELTA_L_85_10INCH_TOP_DP")
	)
	(segment
		(start 290.212272 -8.488934)
		(end 290.535106 -8.262366)
		(width 0.13208)
		(layer "F.Cu")
		(net "DELTA_L_85_10INCH_TOP_DP")
	)
	(segment
		(start 308.464458 -8.269478)
		(end 309.501794 -2.387092)
		(width 0.13208)
		(layer "F.Cu")
		(net "DELTA_L_85_10INCH_TOP_DP")
	)
	(segment
		(start 302.889158 -7.899146)
		(end 303.119282 -8.227822)
		(width 0.13208)
		(layer "F.Cu")
		(net "DELTA_L_85_10INCH_TOP_DP")
	)
	(segment
		(start 266.121134 -4.391406)
		(end 266.502642 -2.227834)
		(width 0.13208)
		(layer "F.Cu")
		(net "DELTA_L_85_10INCH_TOP_DP")
	)
	(segment
		(start 294.113966 -8.296148)
		(end 295.169336 -2.310638)
		(width 0.13208)
		(layer "F.Cu")
		(net "DELTA_L_85_10INCH_TOP_DP")
	)
	(segment
		(start 313.868816 -8.230362)
		(end 315.313314 -8.48487)
		(width 0.13208)
		(layer "F.Cu")
		(net "DELTA_L_85_10INCH_TOP_DP")
	)
	(segment
		(start 270.08328 -2.254504)
		(end 270.235934 -2.147316)
		(width 0.13208)
		(layer "F.Cu")
		(net "DELTA_L_85_10INCH_TOP_DP")
	)
	(segment
		(start 292.120066 -7.94512)
		(end 292.346634 -8.267954)
		(width 0.13208)
		(layer "F.Cu")
		(net "DELTA_L_85_10INCH_TOP_DP")
	)
	(segment
		(start 266.502642 -2.227834)
		(end 266.655296 -2.1209)
		(width 0.13208)
		(layer "F.Cu")
		(net "DELTA_L_85_10INCH_TOP_DP")
	)
	(segment
		(start 284.957012 -7.906004)
		(end 285.18358 -8.228838)
		(width 0.13208)
		(layer "F.Cu")
		(net "DELTA_L_85_10INCH_TOP_DP")
	)
	(segment
		(start 268.701012 -8.459978)
		(end 269.029434 -8.229346)
		(width 0.13208)
		(layer "F.Cu")
		(net "DELTA_L_85_10INCH_TOP_DP")
	)
	(segment
		(start 266.655296 -2.1209)
		(end 267.87856 -2.336546)
		(width 0.13208)
		(layer "F.Cu")
		(net "DELTA_L_85_10INCH_TOP_DP")
	)
	(segment
		(start 270.235934 -2.147316)
		(end 271.459198 -2.362962)
		(width 0.13208)
		(layer "F.Cu")
		(net "DELTA_L_85_10INCH_TOP_DP")
	)
	(segment
		(start 299.513752 -8.283702)
		(end 300.958504 -8.53821)
		(width 0.13208)
		(layer "F.Cu")
		(net "DELTA_L_85_10INCH_TOP_DP")
	)
	(segment
		(start 297.70324 -8.272272)
		(end 298.749974 -2.337054)
		(width 0.13208)
		(layer "F.Cu")
		(net "DELTA_L_85_10INCH_TOP_DP")
	)
	(segment
		(start 285.18358 -8.228838)
		(end 286.628078 -8.4836)
		(width 0.13208)
		(layer "F.Cu")
		(net "DELTA_L_85_10INCH_TOP_DP")
	)
	(segment
		(start 317.223394 -7.931912)
		(end 317.449454 -8.255)
		(width 0.13208)
		(layer "F.Cu")
		(net "DELTA_L_85_10INCH_TOP_DP")
	)
	(segment
		(start 281.60345 -8.228076)
		(end 283.038042 -8.48106)
		(width 0.13208)
		(layer "F.Cu")
		(net "DELTA_L_85_10INCH_TOP_DP")
	)
	(segment
		(start 296.65295 -2.57175)
		(end 295.70934 -7.921244)
		(width 0.13208)
		(layer "F.Cu")
		(net "DELTA_L_85_10INCH_TOP_DP")
	)
	(segment
		(start 279.455626 -8.46709)
		(end 279.784048 -8.236458)
		(width 0.13208)
		(layer "F.Cu")
		(net "DELTA_L_85_10INCH_TOP_DP")
	)
	(segment
		(start 261.667752 -4.946142)
		(end 261.776464 -4.83743)
		(width 0.13208)
		(layer "F.Cu")
		(net "DELTA_L_85_10INCH_TOP_DP")
	)
	(segment
		(start 290.535106 -8.262366)
		(end 291.599366 -2.225548)
		(width 0.13208)
		(layer "F.Cu")
		(net "DELTA_L_85_10INCH_TOP_DP")
	)
	(segment
		(start 313.642756 -7.907274)
		(end 313.868816 -8.230362)
		(width 0.13208)
		(layer "F.Cu")
		(net "DELTA_L_85_10INCH_TOP_DP")
	)
	(segment
		(start 300.23308 -2.598674)
		(end 299.287946 -7.960106)
		(width 0.13208)
		(layer "F.Cu")
		(net "DELTA_L_85_10INCH_TOP_DP")
	)
	(segment
		(start 301.28718 -8.30834)
		(end 302.329596 -2.398776)
		(width 0.13208)
		(layer "F.Cu")
		(net "DELTA_L_85_10INCH_TOP_DP")
	)
	(segment
		(start 275.039836 -2.389378)
		(end 275.147278 -2.54254)
		(width 0.13208)
		(layer "F.Cu")
		(net "DELTA_L_85_10INCH_TOP_DP")
	)
	(segment
		(start 317.449454 -8.255)
		(end 318.893952 -8.509508)
		(width 0.13208)
		(layer "F.Cu")
		(net "DELTA_L_85_10INCH_TOP_DP")
	)
	(segment
		(start 300.958504 -8.53821)
		(end 301.28718 -8.30834)
		(width 0.13208)
		(layer "F.Cu")
		(net "DELTA_L_85_10INCH_TOP_DP")
	)
	(segment
		(start 304.554128 -8.48106)
		(end 304.882804 -8.250682)
		(width 0.13208)
		(layer "F.Cu")
		(net "DELTA_L_85_10INCH_TOP_DP")
	)
	(segment
		(start 271.56664 -2.516124)
		(end 270.625824 -7.849616)
		(width 0.13208)
		(layer "F.Cu")
		(net "DELTA_L_85_10INCH_TOP_DP")
	)
	(segment
		(start 309.654702 -2.279904)
		(end 310.877966 -2.49555)
		(width 0.13208)
		(layer "F.Cu")
		(net "DELTA_L_85_10INCH_TOP_DP")
	)
	(segment
		(start 311.728866 -8.482838)
		(end 312.051954 -8.256778)
		(width 0.13208)
		(layer "F.Cu")
		(net "DELTA_L_85_10INCH_TOP_DP")
	)
	(segment
		(start 298.902882 -2.229866)
		(end 300.125892 -2.445512)
		(width 0.13208)
		(layer "F.Cu")
		(net "DELTA_L_85_10INCH_TOP_DP")
	)
	(segment
		(start 321.630294 -2.510536)
		(end 321.737482 -2.663698)
		(width 0.13208)
		(layer "F.Cu")
		(net "DELTA_L_85_10INCH_TOP_DP")
	)
	(segment
		(start 288.541206 -7.911338)
		(end 288.767774 -8.234172)
		(width 0.13208)
		(layer "F.Cu")
		(net "DELTA_L_85_10INCH_TOP_DP")
	)
	(segment
		(start 295.70934 -7.921244)
		(end 295.935908 -8.244078)
		(width 0.13208)
		(layer "F.Cu")
		(net "DELTA_L_85_10INCH_TOP_DP")
	)
	(segment
		(start 318.893952 -8.509508)
		(end 319.21704 -8.283448)
		(width 0.13208)
		(layer "F.Cu")
		(net "DELTA_L_85_10INCH_TOP_DP")
	)
	(segment
		(start 280.825194 -2.333752)
		(end 280.977848 -2.226564)
		(width 0.13208)
		(layer "F.Cu")
		(net "DELTA_L_85_10INCH_TOP_DP")
	)
	(segment
		(start 282.201112 -2.44221)
		(end 282.308554 -2.595372)
		(width 0.13208)
		(layer "F.Cu")
		(net "DELTA_L_85_10INCH_TOP_DP")
	)
	(segment
		(start 284.413198 -2.317242)
		(end 284.566106 -2.210054)
		(width 0.13208)
		(layer "F.Cu")
		(net "DELTA_L_85_10INCH_TOP_DP")
	)
	(segment
		(start 307.40096 -2.643632)
		(end 306.471066 -7.917942)
		(width 0.13208)
		(layer "F.Cu")
		(net "DELTA_L_85_10INCH_TOP_DP")
	)
	(segment
		(start 310.877966 -2.49555)
		(end 310.985154 -2.648712)
		(width 0.13208)
		(layer "F.Cu")
		(net "DELTA_L_85_10INCH_TOP_DP")
	)
	(segment
		(start 267.035534 -7.878318)
		(end 267.266166 -8.20674)
		(width 0.13208)
		(layer "F.Cu")
		(net "DELTA_L_85_10INCH_TOP_DP")
	)
	(segment
		(start 273.816572 -2.173732)
		(end 275.039836 -2.389378)
		(width 0.13208)
		(layer "F.Cu")
		(net "DELTA_L_85_10INCH_TOP_DP")
	)
	(segment
		(start 295.322498 -2.202942)
		(end 295.322498 -2.203196)
		(width 0.13208)
		(layer "F.Cu")
		(net "DELTA_L_85_10INCH_TOP_DP")
	)
	(segment
		(start 274.216876 -7.817358)
		(end 274.447508 -8.146288)
		(width 0.13208)
		(layer "F.Cu")
		(net "DELTA_L_85_10INCH_TOP_DP")
	)
	(segment
		(start 279.784048 -8.236458)
		(end 280.825194 -2.333752)
		(width 0.13208)
		(layer "F.Cu")
		(net "DELTA_L_85_10INCH_TOP_DP")
	)
	(segment
		(start 286.628078 -8.4836)
		(end 286.950912 -8.257032)
		(width 0.13208)
		(layer "F.Cu")
		(net "DELTA_L_85_10INCH_TOP_DP")
	)
	(segment
		(start 295.935908 -8.244078)
		(end 297.380406 -8.49884)
		(width 0.13208)
		(layer "F.Cu")
		(net "DELTA_L_85_10INCH_TOP_DP")
	)
	(segment
		(start 277.39721 -2.200148)
		(end 278.620474 -2.415794)
		(width 0.13208)
		(layer "F.Cu")
		(net "DELTA_L_85_10INCH_TOP_DP")
	)
	(segment
		(start 270.856456 -8.178038)
		(end 272.291302 -8.431276)
		(width 0.13208)
		(layer "F.Cu")
		(net "DELTA_L_85_10INCH_TOP_DP")
	)
	(segment
		(start 322.47713 -8.525002)
		(end 322.799964 -8.298434)
		(width 0.13208)
		(layer "F.Cu")
		(net "DELTA_L_85_10INCH_TOP_DP")
	)
	(segment
		(start 291.599366 -2.225548)
		(end 291.752528 -2.11836)
		(width 0.13208)
		(layer "F.Cu")
		(net "DELTA_L_85_10INCH_TOP_DP")
	)
	(segment
		(start 302.48225 -2.291588)
		(end 303.705514 -2.507234)
		(width 0.13208)
		(layer "F.Cu")
		(net "DELTA_L_85_10INCH_TOP_DP")
	)
	(segment
		(start 302.329596 -2.398776)
		(end 302.48225 -2.291588)
		(width 0.13208)
		(layer "F.Cu")
		(net "DELTA_L_85_10INCH_TOP_DP")
	)
	(segment
		(start 282.308554 -2.595372)
		(end 281.372818 -7.899908)
		(width 0.13208)
		(layer "F.Cu")
		(net "DELTA_L_85_10INCH_TOP_DP")
	)
	(segment
		(start 272.619724 -8.200644)
		(end 273.663918 -2.28092)
		(width 0.13208)
		(layer "F.Cu")
		(net "DELTA_L_85_10INCH_TOP_DP")
	)
	(segment
		(start 323.323204 -5.329682)
		(end 323.82714 -4.825746)
		(width 0.13208)
		(layer "F.Cu")
		(net "DELTA_L_85_10INCH_TOP_DP")
	)
	(segment
		(start 288.1503 -2.21488)
		(end 289.373564 -2.430526)
		(width 0.13208)
		(layer "F.Cu")
		(net "DELTA_L_85_10INCH_TOP_DP")
	)
	(segment
		(start 293.082726 -2.48666)
		(end 292.120066 -7.94512)
		(width 0.13208)
		(layer "F.Cu")
		(net "DELTA_L_85_10INCH_TOP_DP")
	)
	(segment
		(start 306.697126 -8.24103)
		(end 308.141624 -8.495538)
		(width 0.13208)
		(layer "F.Cu")
		(net "DELTA_L_85_10INCH_TOP_DP")
	)
	(segment
		(start 304.882804 -8.250682)
		(end 305.9176 -2.382266)
		(width 0.13208)
		(layer "F.Cu")
		(net "DELTA_L_85_10INCH_TOP_DP")
	)
	(segment
		(start 281.372818 -7.899908)
		(end 281.60345 -8.228076)
		(width 0.13208)
		(layer "F.Cu")
		(net "DELTA_L_85_10INCH_TOP_DP")
	)
	(segment
		(start 319.21704 -8.283448)
		(end 320.254122 -2.402078)
		(width 0.13208)
		(layer "F.Cu")
		(net "DELTA_L_85_10INCH_TOP_DP")
	)
	(segment
		(start 299.287946 -7.960106)
		(end 299.513752 -8.283702)
		(width 0.13208)
		(layer "F.Cu")
		(net "DELTA_L_85_10INCH_TOP_DP")
	)
	(segment
		(start 285.896558 -2.578862)
		(end 284.957012 -7.906004)
		(width 0.13208)
		(layer "F.Cu")
		(net "DELTA_L_85_10INCH_TOP_DP")
	)
	(segment
		(start 275.147278 -2.54254)
		(end 274.216876 -7.817358)
		(width 0.13208)
		(layer "F.Cu")
		(net "DELTA_L_85_10INCH_TOP_DP")
	)
	(segment
		(start 303.705514 -2.507234)
		(end 303.812956 -2.660396)
		(width 0.13208)
		(layer "F.Cu")
		(net "DELTA_L_85_10INCH_TOP_DP")
	)
	(segment
		(start 279.001982 -2.507996)
		(end 278.064214 -7.82447)
		(width 0.13208)
		(layer "F.Cu")
		(net "DELTA_L_85_10INCH_TOP_DN")
	)
	(segment
		(start 315.252608 -8.211058)
		(end 315.399674 -8.107934)
		(width 0.13208)
		(layer "F.Cu")
		(net "DELTA_L_85_10INCH_TOP_DN")
	)
	(segment
		(start 274.490942 -7.756652)
		(end 274.59813 -7.90956)
		(width 0.13208)
		(layer "F.Cu")
		(net "DELTA_L_85_10INCH_TOP_DN")
	)
	(segment
		(start 296.08653 -8.00735)
		(end 297.319446 -8.224774)
		(width 0.13208)
		(layer "F.Cu")
		(net "DELTA_L_85_10INCH_TOP_DN")
	)
	(segment
		(start 284.505146 -1.935988)
		(end 285.939992 -2.188972)
		(width 0.13208)
		(layer "F.Cu")
		(net "DELTA_L_85_10INCH_TOP_DN")
	)
	(segment
		(start 289.52444 -2.193798)
		(end 289.754564 -2.522982)
		(width 0.13208)
		(layer "F.Cu")
		(net "DELTA_L_85_10INCH_TOP_DN")
	)
	(segment
		(start 306.744878 -7.857236)
		(end 306.848002 -8.004302)
		(width 0.13208)
		(layer "F.Cu")
		(net "DELTA_L_85_10INCH_TOP_DN")
	)
	(segment
		(start 298.842176 -1.956054)
		(end 300.276768 -2.208784)
		(width 0.13208)
		(layer "F.Cu")
		(net "DELTA_L_85_10INCH_TOP_DN")
	)
	(segment
		(start 270.175228 -1.873504)
		(end 271.60982 -2.126234)
		(width 0.13208)
		(layer "F.Cu")
		(net "DELTA_L_85_10INCH_TOP_DN")
	)
	(segment
		(start 271.60982 -2.126234)
		(end 271.840706 -2.455164)
		(width 0.13208)
		(layer "F.Cu")
		(net "DELTA_L_85_10INCH_TOP_DN")
	)
	(segment
		(start 299.664628 -8.046974)
		(end 300.897798 -8.264398)
		(width 0.13208)
		(layer "F.Cu")
		(net "DELTA_L_85_10INCH_TOP_DN")
	)
	(segment
		(start 288.815272 -7.850378)
		(end 288.918396 -7.997444)
		(width 0.13208)
		(layer "F.Cu")
		(net "DELTA_L_85_10INCH_TOP_DN")
	)
	(segment
		(start 314.63107 -2.162302)
		(end 314.86094 -2.490978)
		(width 0.13208)
		(layer "F.Cu")
		(net "DELTA_L_85_10INCH_TOP_DN")
	)
	(segment
		(start 316.43701 -2.224278)
		(end 316.766194 -1.994154)
		(width 0.13208)
		(layer "F.Cu")
		(net "DELTA_L_85_10INCH_TOP_DN")
	)
	(segment
		(start 300.897798 -8.264398)
		(end 301.050452 -8.157464)
		(width 0.13208)
		(layer "F.Cu")
		(net "DELTA_L_85_10INCH_TOP_DN")
	)
	(segment
		(start 285.939992 -2.188972)
		(end 286.170624 -2.517902)
		(width 0.13208)
		(layer "F.Cu")
		(net "DELTA_L_85_10INCH_TOP_DN")
	)
	(segment
		(start 320.346578 -2.021078)
		(end 321.78117 -2.273808)
		(width 0.13208)
		(layer "F.Cu")
		(net "DELTA_L_85_10INCH_TOP_DN")
	)
	(segment
		(start 300.276768 -2.208784)
		(end 300.506892 -2.537968)
		(width 0.13208)
		(layer "F.Cu")
		(net "DELTA_L_85_10INCH_TOP_DN")
	)
	(segment
		(start 315.399674 -8.107934)
		(end 316.43701 -2.224278)
		(width 0.13208)
		(layer "F.Cu")
		(net "DELTA_L_85_10INCH_TOP_DN")
	)
	(segment
		(start 313.196224 -1.909572)
		(end 314.63107 -2.162302)
		(width 0.13208)
		(layer "F.Cu")
		(net "DELTA_L_85_10INCH_TOP_DN")
	)
	(segment
		(start 266.265914 -2.076958)
		(end 266.59459 -1.847088)
		(width 0.13208)
		(layer "F.Cu")
		(net "DELTA_L_85_10INCH_TOP_DN")
	)
	(segment
		(start 278.171402 -7.977124)
		(end 279.394666 -8.193024)
		(width 0.13208)
		(layer "F.Cu")
		(net "DELTA_L_85_10INCH_TOP_DN")
	)
	(segment
		(start 289.754564 -2.522982)
		(end 288.815272 -7.850378)
		(width 0.13208)
		(layer "F.Cu")
		(net "DELTA_L_85_10INCH_TOP_DN")
	)
	(segment
		(start 275.821394 -8.12546)
		(end 275.973794 -8.018272)
		(width 0.13208)
		(layer "F.Cu")
		(net "DELTA_L_85_10INCH_TOP_DN")
	)
	(segment
		(start 306.009802 -2.001012)
		(end 307.444394 -2.253996)
		(width 0.13208)
		(layer "F.Cu")
		(net "DELTA_L_85_10INCH_TOP_DN")
	)
	(segment
		(start 272.382996 -8.050022)
		(end 273.42719 -2.130044)
		(width 0.13208)
		(layer "F.Cu")
		(net "DELTA_L_85_10INCH_TOP_DN")
	)
	(segment
		(start 328.183748 -4.566666)
		(end 328.304144 -4.44627)
		(width 0.13208)
		(layer "F.Cu")
		(net "DELTA_L_85_10INCH_TOP_DN")
	)
	(segment
		(start 277.336504 -1.926336)
		(end 278.771096 -2.179066)
		(width 0.13208)
		(layer "F.Cu")
		(net "DELTA_L_85_10INCH_TOP_DN")
	)
	(segment
		(start 314.86094 -2.490978)
		(end 313.916568 -7.846568)
		(width 0.13208)
		(layer "F.Cu")
		(net "DELTA_L_85_10INCH_TOP_DN")
	)
	(segment
		(start 266.59459 -1.847088)
		(end 268.029182 -2.099818)
		(width 0.13208)
		(layer "F.Cu")
		(net "DELTA_L_85_10INCH_TOP_DN")
	)
	(segment
		(start 310.33212 -7.844536)
		(end 310.435244 -7.991602)
		(width 0.13208)
		(layer "F.Cu")
		(net "DELTA_L_85_10INCH_TOP_DN")
	)
	(segment
		(start 311.028842 -2.258822)
		(end 311.258966 -2.588006)
		(width 0.13208)
		(layer "F.Cu")
		(net "DELTA_L_85_10INCH_TOP_DN")
	)
	(segment
		(start 271.007078 -7.94131)
		(end 272.230342 -8.15721)
		(width 0.13208)
		(layer "F.Cu")
		(net "DELTA_L_85_10INCH_TOP_DN")
	)
	(segment
		(start 261.67334 -4.44627)
		(end 261.80542 -4.57835)
		(width 0.13208)
		(layer "F.Cu")
		(net "DELTA_L_85_10INCH_TOP_DN")
	)
	(segment
		(start 311.258966 -2.588006)
		(end 310.33212 -7.844536)
		(width 0.13208)
		(layer "F.Cu")
		(net "DELTA_L_85_10INCH_TOP_DN")
	)
	(segment
		(start 290.298378 -8.111744)
		(end 291.362638 -2.074672)
		(width 0.13208)
		(layer "F.Cu")
		(net "DELTA_L_85_10INCH_TOP_DN")
	)
	(segment
		(start 308.080918 -8.221726)
		(end 308.22773 -8.118602)
		(width 0.13208)
		(layer "F.Cu")
		(net "DELTA_L_85_10INCH_TOP_DN")
	)
	(segment
		(start 309.593996 -2.005838)
		(end 311.028842 -2.258822)
		(width 0.13208)
		(layer "F.Cu")
		(net "DELTA_L_85_10INCH_TOP_DN")
	)
	(segment
		(start 275.973794 -8.018272)
		(end 277.007828 -2.15646)
		(width 0.13208)
		(layer "F.Cu")
		(net "DELTA_L_85_10INCH_TOP_DN")
	)
	(segment
		(start 322.41617 -8.250936)
		(end 322.563236 -8.147812)
		(width 0.13208)
		(layer "F.Cu")
		(net "DELTA_L_85_10INCH_TOP_DN")
	)
	(segment
		(start 296.926762 -2.511044)
		(end 295.983406 -7.860284)
		(width 0.13208)
		(layer "F.Cu")
		(net "DELTA_L_85_10INCH_TOP_DN")
	)
	(segment
		(start 283.12999 -8.100314)
		(end 284.17647 -2.16662)
		(width 0.13208)
		(layer "F.Cu")
		(net "DELTA_L_85_10INCH_TOP_DN")
	)
	(segment
		(start 268.792706 -8.078724)
		(end 269.846552 -2.103628)
		(width 0.13208)
		(layer "F.Cu")
		(net "DELTA_L_85_10INCH_TOP_DN")
	)
	(segment
		(start 268.640052 -8.185912)
		(end 268.792706 -8.078724)
		(width 0.13208)
		(layer "F.Cu")
		(net "DELTA_L_85_10INCH_TOP_DN")
	)
	(segment
		(start 316.766194 -1.994154)
		(end 318.200786 -2.247138)
		(width 0.13208)
		(layer "F.Cu")
		(net "DELTA_L_85_10INCH_TOP_DN")
	)
	(segment
		(start 321.079876 -7.886446)
		(end 321.183 -8.033512)
		(width 0.13208)
		(layer "F.Cu")
		(net "DELTA_L_85_10INCH_TOP_DN")
	)
	(segment
		(start 282.351734 -2.205482)
		(end 282.58262 -2.534412)
		(width 0.13208)
		(layer "F.Cu")
		(net "DELTA_L_85_10INCH_TOP_DN")
	)
	(segment
		(start 261.80542 -4.57835)
		(end 265.49477 -4.57835)
		(width 0.13208)
		(layer "F.Cu")
		(net "DELTA_L_85_10INCH_TOP_DN")
	)
	(segment
		(start 280.588466 -2.182876)
		(end 280.917142 -1.952752)
		(width 0.13208)
		(layer "F.Cu")
		(net "DELTA_L_85_10INCH_TOP_DN")
	)
	(segment
		(start 292.394132 -7.88416)
		(end 292.497256 -8.031226)
		(width 0.13208)
		(layer "F.Cu")
		(net "DELTA_L_85_10INCH_TOP_DN")
	)
	(segment
		(start 285.334202 -7.99211)
		(end 286.567118 -8.209534)
		(width 0.13208)
		(layer "F.Cu")
		(net "DELTA_L_85_10INCH_TOP_DN")
	)
	(segment
		(start 288.08934 -1.940814)
		(end 289.52444 -2.193798)
		(width 0.13208)
		(layer "F.Cu")
		(net "DELTA_L_85_10INCH_TOP_DN")
	)
	(segment
		(start 295.261792 -1.92913)
		(end 296.696384 -2.182114)
		(width 0.13208)
		(layer "F.Cu")
		(net "DELTA_L_85_10INCH_TOP_DN")
	)
	(segment
		(start 298.513246 -2.186178)
		(end 298.842176 -1.956054)
		(width 0.13208)
		(layer "F.Cu")
		(net "DELTA_L_85_10INCH_TOP_DN")
	)
	(segment
		(start 318.980312 -8.132572)
		(end 320.017394 -2.251202)
		(width 0.13208)
		(layer "F.Cu")
		(net "DELTA_L_85_10INCH_TOP_DN")
	)
	(segment
		(start 318.431164 -2.576068)
		(end 317.497206 -7.871206)
		(width 0.13208)
		(layer "F.Cu")
		(net "DELTA_L_85_10INCH_TOP_DN")
	)
	(segment
		(start 303.270158 -7.991094)
		(end 304.493422 -8.206994)
		(width 0.13208)
		(layer "F.Cu")
		(net "DELTA_L_85_10INCH_TOP_DN")
	)
	(segment
		(start 308.22773 -8.118602)
		(end 309.265066 -2.23647)
		(width 0.13208)
		(layer "F.Cu")
		(net "DELTA_L_85_10INCH_TOP_DN")
	)
	(segment
		(start 303.856136 -2.270506)
		(end 304.087022 -2.599436)
		(width 0.13208)
		(layer "F.Cu")
		(net "DELTA_L_85_10INCH_TOP_DN")
	)
	(segment
		(start 278.064214 -7.82447)
		(end 278.171402 -7.977124)
		(width 0.13208)
		(layer "F.Cu")
		(net "DELTA_L_85_10INCH_TOP_DN")
	)
	(segment
		(start 268.260068 -2.428748)
		(end 267.3096 -7.817358)
		(width 0.13208)
		(layer "F.Cu")
		(net "DELTA_L_85_10INCH_TOP_DN")
	)
	(segment
		(start 286.714184 -8.10641)
		(end 287.760664 -2.171446)
		(width 0.13208)
		(layer "F.Cu")
		(net "DELTA_L_85_10INCH_TOP_DN")
	)
	(segment
		(start 265.49477 -4.57835)
		(end 265.882374 -4.253484)
		(width 0.13208)
		(layer "F.Cu")
		(net "DELTA_L_85_10INCH_TOP_DN")
	)
	(segment
		(start 322.563236 -8.147812)
		(end 323.082158 -5.204206)
		(width 0.13208)
		(layer "F.Cu")
		(net "DELTA_L_85_10INCH_TOP_DN")
	)
	(segment
		(start 314.019692 -7.993634)
		(end 315.252608 -8.211058)
		(width 0.13208)
		(layer "F.Cu")
		(net "DELTA_L_85_10INCH_TOP_DN")
	)
	(segment
		(start 278.771096 -2.179066)
		(end 279.001982 -2.507996)
		(width 0.13208)
		(layer "F.Cu")
		(net "DELTA_L_85_10INCH_TOP_DN")
	)
	(segment
		(start 291.691822 -1.844548)
		(end 293.126668 -2.097278)
		(width 0.13208)
		(layer "F.Cu")
		(net "DELTA_L_85_10INCH_TOP_DN")
	)
	(segment
		(start 304.493422 -8.206994)
		(end 304.646076 -8.10006)
		(width 0.13208)
		(layer "F.Cu")
		(net "DELTA_L_85_10INCH_TOP_DN")
	)
	(segment
		(start 328.304144 -4.44627)
		(end 328.414888 -4.44627)
		(width 0.13208)
		(layer "F.Cu")
		(net "DELTA_L_85_10INCH_TOP_DN")
	)
	(segment
		(start 310.435244 -7.991602)
		(end 311.66816 -8.209026)
		(width 0.13208)
		(layer "F.Cu")
		(net "DELTA_L_85_10INCH_TOP_DN")
	)
	(segment
		(start 294.932608 -2.159254)
		(end 295.261792 -1.92913)
		(width 0.13208)
		(layer "F.Cu")
		(net "DELTA_L_85_10INCH_TOP_DN")
	)
	(segment
		(start 279.394666 -8.193024)
		(end 279.54732 -8.085836)
		(width 0.13208)
		(layer "F.Cu")
		(net "DELTA_L_85_10INCH_TOP_DN")
	)
	(segment
		(start 302.421544 -2.017776)
		(end 303.856136 -2.270506)
		(width 0.13208)
		(layer "F.Cu")
		(net "DELTA_L_85_10INCH_TOP_DN")
	)
	(segment
		(start 293.730172 -8.24865)
		(end 293.877238 -8.145526)
		(width 0.13208)
		(layer "F.Cu")
		(net "DELTA_L_85_10INCH_TOP_DN")
	)
	(segment
		(start 320.017394 -2.251202)
		(end 320.346578 -2.021078)
		(width 0.13208)
		(layer "F.Cu")
		(net "DELTA_L_85_10INCH_TOP_DN")
	)
	(segment
		(start 286.567118 -8.209534)
		(end 286.714184 -8.10641)
		(width 0.13208)
		(layer "F.Cu")
		(net "DELTA_L_85_10INCH_TOP_DN")
	)
	(segment
		(start 312.86704 -2.139696)
		(end 313.196224 -1.909572)
		(width 0.13208)
		(layer "F.Cu")
		(net "DELTA_L_85_10INCH_TOP_DN")
	)
	(segment
		(start 273.42719 -2.130044)
		(end 273.755866 -1.89992)
		(width 0.13208)
		(layer "F.Cu")
		(net "DELTA_L_85_10INCH_TOP_DN")
	)
	(segment
		(start 280.917142 -1.952752)
		(end 282.351734 -2.205482)
		(width 0.13208)
		(layer "F.Cu")
		(net "DELTA_L_85_10INCH_TOP_DN")
	)
	(segment
		(start 307.444394 -2.253996)
		(end 307.675026 -2.582926)
		(width 0.13208)
		(layer "F.Cu")
		(net "DELTA_L_85_10INCH_TOP_DN")
	)
	(segment
		(start 291.362638 -2.074672)
		(end 291.691822 -1.844548)
		(width 0.13208)
		(layer "F.Cu")
		(net "DELTA_L_85_10INCH_TOP_DN")
	)
	(segment
		(start 261.557008 -4.44627)
		(end 261.67334 -4.44627)
		(width 0.13208)
		(layer "F.Cu")
		(net "DELTA_L_85_10INCH_TOP_DN")
	)
	(segment
		(start 286.170624 -2.517902)
		(end 285.231078 -7.845044)
		(width 0.13208)
		(layer "F.Cu")
		(net "DELTA_L_85_10INCH_TOP_DN")
	)
	(segment
		(start 275.421344 -2.48158)
		(end 274.490942 -7.756652)
		(width 0.13208)
		(layer "F.Cu")
		(net "DELTA_L_85_10INCH_TOP_DN")
	)
	(segment
		(start 311.815226 -8.105902)
		(end 312.86704 -2.139696)
		(width 0.13208)
		(layer "F.Cu")
		(net "DELTA_L_85_10INCH_TOP_DN")
	)
	(segment
		(start 297.319446 -8.224774)
		(end 297.466512 -8.12165)
		(width 0.13208)
		(layer "F.Cu")
		(net "DELTA_L_85_10INCH_TOP_DN")
	)
	(segment
		(start 307.675026 -2.582926)
		(end 306.744878 -7.857236)
		(width 0.13208)
		(layer "F.Cu")
		(net "DELTA_L_85_10INCH_TOP_DN")
	)
	(segment
		(start 284.17647 -2.16662)
		(end 284.505146 -1.935988)
		(width 0.13208)
		(layer "F.Cu")
		(net "DELTA_L_85_10INCH_TOP_DN")
	)
	(segment
		(start 306.848002 -8.004302)
		(end 308.080918 -8.221726)
		(width 0.13208)
		(layer "F.Cu")
		(net "DELTA_L_85_10INCH_TOP_DN")
	)
	(segment
		(start 323.719698 -4.566666)
		(end 328.183748 -4.566666)
		(width 0.13208)
		(layer "F.Cu")
		(net "DELTA_L_85_10INCH_TOP_DN")
	)
	(segment
		(start 309.265066 -2.23647)
		(end 309.593996 -2.005838)
		(width 0.13208)
		(layer "F.Cu")
		(net "DELTA_L_85_10INCH_TOP_DN")
	)
	(segment
		(start 267.416788 -7.970012)
		(end 268.640052 -8.185912)
		(width 0.13208)
		(layer "F.Cu")
		(net "DELTA_L_85_10INCH_TOP_DN")
	)
	(segment
		(start 317.60033 -8.018272)
		(end 318.833246 -8.235696)
		(width 0.13208)
		(layer "F.Cu")
		(net "DELTA_L_85_10INCH_TOP_DN")
	)
	(segment
		(start 322.011294 -2.602992)
		(end 321.079876 -7.886446)
		(width 0.13208)
		(layer "F.Cu")
		(net "DELTA_L_85_10INCH_TOP_DN")
	)
	(segment
		(start 290.151312 -8.214868)
		(end 290.298378 -8.111744)
		(width 0.13208)
		(layer "F.Cu")
		(net "DELTA_L_85_10INCH_TOP_DN")
	)
	(segment
		(start 274.59813 -7.90956)
		(end 275.821394 -8.12546)
		(width 0.13208)
		(layer "F.Cu")
		(net "DELTA_L_85_10INCH_TOP_DN")
	)
	(segment
		(start 321.78117 -2.273808)
		(end 322.011294 -2.602992)
		(width 0.13208)
		(layer "F.Cu")
		(net "DELTA_L_85_10INCH_TOP_DN")
	)
	(segment
		(start 275.190458 -2.15265)
		(end 275.421344 -2.48158)
		(width 0.13208)
		(layer "F.Cu")
		(net "DELTA_L_85_10INCH_TOP_DN")
	)
	(segment
		(start 313.916568 -7.846568)
		(end 314.019692 -7.993634)
		(width 0.13208)
		(layer "F.Cu")
		(net "DELTA_L_85_10INCH_TOP_DN")
	)
	(segment
		(start 295.983406 -7.860284)
		(end 296.08653 -8.00735)
		(width 0.13208)
		(layer "F.Cu")
		(net "DELTA_L_85_10INCH_TOP_DN")
	)
	(segment
		(start 267.3096 -7.817358)
		(end 267.416788 -7.970012)
		(width 0.13208)
		(layer "F.Cu")
		(net "DELTA_L_85_10INCH_TOP_DN")
	)
	(segment
		(start 299.561758 -7.899654)
		(end 299.664628 -8.046974)
		(width 0.13208)
		(layer "F.Cu")
		(net "DELTA_L_85_10INCH_TOP_DN")
	)
	(segment
		(start 270.89989 -7.788656)
		(end 271.007078 -7.94131)
		(width 0.13208)
		(layer "F.Cu")
		(net "DELTA_L_85_10INCH_TOP_DN")
	)
	(segment
		(start 318.833246 -8.235696)
		(end 318.980312 -8.132572)
		(width 0.13208)
		(layer "F.Cu")
		(net "DELTA_L_85_10INCH_TOP_DN")
	)
	(segment
		(start 265.882374 -4.253484)
		(end 266.265914 -2.076958)
		(width 0.13208)
		(layer "F.Cu")
		(net "DELTA_L_85_10INCH_TOP_DN")
	)
	(segment
		(start 301.050452 -8.157464)
		(end 302.092868 -2.2479)
		(width 0.13208)
		(layer "F.Cu")
		(net "DELTA_L_85_10INCH_TOP_DN")
	)
	(segment
		(start 281.646884 -7.838948)
		(end 281.754072 -7.991348)
		(width 0.13208)
		(layer "F.Cu")
		(net "DELTA_L_85_10INCH_TOP_DN")
	)
	(segment
		(start 271.840706 -2.455164)
		(end 270.89989 -7.788656)
		(width 0.13208)
		(layer "F.Cu")
		(net "DELTA_L_85_10INCH_TOP_DN")
	)
	(segment
		(start 297.466512 -8.12165)
		(end 298.513246 -2.186178)
		(width 0.13208)
		(layer "F.Cu")
		(net "DELTA_L_85_10INCH_TOP_DN")
	)
	(segment
		(start 285.231078 -7.845044)
		(end 285.334202 -7.99211)
		(width 0.13208)
		(layer "F.Cu")
		(net "DELTA_L_85_10INCH_TOP_DN")
	)
	(segment
		(start 269.846552 -2.103628)
		(end 270.175228 -1.873504)
		(width 0.13208)
		(layer "F.Cu")
		(net "DELTA_L_85_10INCH_TOP_DN")
	)
	(segment
		(start 287.760664 -2.171446)
		(end 288.08934 -1.940814)
		(width 0.13208)
		(layer "F.Cu")
		(net "DELTA_L_85_10INCH_TOP_DN")
	)
	(segment
		(start 321.183 -8.033512)
		(end 322.41617 -8.250936)
		(width 0.13208)
		(layer "F.Cu")
		(net "DELTA_L_85_10INCH_TOP_DN")
	)
	(segment
		(start 304.646076 -8.10006)
		(end 305.680872 -2.231644)
		(width 0.13208)
		(layer "F.Cu")
		(net "DELTA_L_85_10INCH_TOP_DN")
	)
	(segment
		(start 293.877238 -8.145526)
		(end 294.932608 -2.159254)
		(width 0.13208)
		(layer "F.Cu")
		(net "DELTA_L_85_10INCH_TOP_DN")
	)
	(segment
		(start 272.230342 -8.15721)
		(end 272.382996 -8.050022)
		(width 0.13208)
		(layer "F.Cu")
		(net "DELTA_L_85_10INCH_TOP_DN")
	)
	(segment
		(start 268.029182 -2.099818)
		(end 268.260068 -2.428748)
		(width 0.13208)
		(layer "F.Cu")
		(net "DELTA_L_85_10INCH_TOP_DN")
	)
	(segment
		(start 303.16297 -7.83844)
		(end 303.270158 -7.991094)
		(width 0.13208)
		(layer "F.Cu")
		(net "DELTA_L_85_10INCH_TOP_DN")
	)
	(segment
		(start 323.082158 -5.204206)
		(end 323.719698 -4.566666)
		(width 0.13208)
		(layer "F.Cu")
		(net "DELTA_L_85_10INCH_TOP_DN")
	)
	(segment
		(start 311.66816 -8.209026)
		(end 311.815226 -8.105902)
		(width 0.13208)
		(layer "F.Cu")
		(net "DELTA_L_85_10INCH_TOP_DN")
	)
	(segment
		(start 304.087022 -2.599436)
		(end 303.16297 -7.83844)
		(width 0.13208)
		(layer "F.Cu")
		(net "DELTA_L_85_10INCH_TOP_DN")
	)
	(segment
		(start 279.54732 -8.085836)
		(end 280.588466 -2.182876)
		(width 0.13208)
		(layer "F.Cu")
		(net "DELTA_L_85_10INCH_TOP_DN")
	)
	(segment
		(start 302.092868 -2.2479)
		(end 302.421544 -2.017776)
		(width 0.13208)
		(layer "F.Cu")
		(net "DELTA_L_85_10INCH_TOP_DN")
	)
	(segment
		(start 317.497206 -7.871206)
		(end 317.60033 -8.018272)
		(width 0.13208)
		(layer "F.Cu")
		(net "DELTA_L_85_10INCH_TOP_DN")
	)
	(segment
		(start 300.506892 -2.537968)
		(end 299.561758 -7.899654)
		(width 0.13208)
		(layer "F.Cu")
		(net "DELTA_L_85_10INCH_TOP_DN")
	)
	(segment
		(start 305.680872 -2.231644)
		(end 306.009802 -2.001012)
		(width 0.13208)
		(layer "F.Cu")
		(net "DELTA_L_85_10INCH_TOP_DN")
	)
	(segment
		(start 293.126668 -2.097278)
		(end 293.356538 -2.425954)
		(width 0.13208)
		(layer "F.Cu")
		(net "DELTA_L_85_10INCH_TOP_DN")
	)
	(segment
		(start 277.007828 -2.15646)
		(end 277.336504 -1.926336)
		(width 0.13208)
		(layer "F.Cu")
		(net "DELTA_L_85_10INCH_TOP_DN")
	)
	(segment
		(start 292.497256 -8.031226)
		(end 293.730172 -8.24865)
		(width 0.13208)
		(layer "F.Cu")
		(net "DELTA_L_85_10INCH_TOP_DN")
	)
	(segment
		(start 273.755866 -1.89992)
		(end 275.190458 -2.15265)
		(width 0.13208)
		(layer "F.Cu")
		(net "DELTA_L_85_10INCH_TOP_DN")
	)
	(segment
		(start 296.696384 -2.182114)
		(end 296.926762 -2.511044)
		(width 0.13208)
		(layer "F.Cu")
		(net "DELTA_L_85_10INCH_TOP_DN")
	)
	(segment
		(start 318.200786 -2.247138)
		(end 318.431164 -2.576068)
		(width 0.13208)
		(layer "F.Cu")
		(net "DELTA_L_85_10INCH_TOP_DN")
	)
	(segment
		(start 282.977336 -8.207248)
		(end 283.12999 -8.100314)
		(width 0.13208)
		(layer "F.Cu")
		(net "DELTA_L_85_10INCH_TOP_DN")
	)
	(segment
		(start 288.918396 -7.997444)
		(end 290.151312 -8.214868)
		(width 0.13208)
		(layer "F.Cu")
		(net "DELTA_L_85_10INCH_TOP_DN")
	)
	(segment
		(start 293.356538 -2.425954)
		(end 292.394132 -7.88416)
		(width 0.13208)
		(layer "F.Cu")
		(net "DELTA_L_85_10INCH_TOP_DN")
	)
	(segment
		(start 282.58262 -2.534412)
		(end 281.646884 -7.838948)
		(width 0.13208)
		(layer "F.Cu")
		(net "DELTA_L_85_10INCH_TOP_DN")
	)
	(segment
		(start 281.754072 -7.991348)
		(end 282.977336 -8.207248)
		(width 0.13208)
		(layer "F.Cu")
		(net "DELTA_L_85_10INCH_TOP_DN")
	)
	(segment
		(start 249.82932 5.710936)
		(end 249.148346 5.8928)
		(width 0.13208)
		(layer "B.Cu")
		(net "DELTA_L_85_10INCH_IN4_DP")
	)
	(segment
		(start 182.97144 5.710936)
		(end 183.652414 5.8928)
		(width 0.13208)
		(layer "B.Cu")
		(net "DELTA_L_85_10INCH_IN4_DP")
	)
	(segment
		(start 241.926872 3.533902)
		(end 243.285264 3.29438)
		(width 0.14732)
		(layer "In11.Cu")
		(net "DELTA_L_85_10INCH_IN4_DP")
	)
	(segment
		(start 199.936608 3.423412)
		(end 201.174604 10.444734)
		(width 0.14732)
		(layer "In11.Cu")
		(net "DELTA_L_85_10INCH_IN4_DP")
	)
	(segment
		(start 238.880904 9.543542)
		(end 237.842552 3.654298)
		(width 0.14732)
		(layer "In11.Cu")
		(net "DELTA_L_85_10INCH_IN4_DP")
	)
	(segment
		(start 189.30874 10.464546)
		(end 189.665356 10.714736)
		(width 0.14732)
		(layer "In11.Cu")
		(net "DELTA_L_85_10INCH_IN4_DP")
	)
	(segment
		(start 230.05542 3.520186)
		(end 231.413812 3.28041)
		(width 0.14732)
		(layer "In11.Cu")
		(net "DELTA_L_85_10INCH_IN4_DP")
	)
	(segment
		(start 218.075002 3.737356)
		(end 218.194382 3.566414)
		(width 0.14732)
		(layer "In11.Cu")
		(net "DELTA_L_85_10INCH_IN4_DP")
	)
	(segment
		(start 198.288656 3.714242)
		(end 198.408036 3.543808)
		(width 0.14732)
		(layer "In11.Cu")
		(net "DELTA_L_85_10INCH_IN4_DP")
	)
	(segment
		(start 189.665356 10.714736)
		(end 191.247522 10.435844)
		(width 0.14732)
		(layer "In11.Cu")
		(net "DELTA_L_85_10INCH_IN4_DP")
	)
	(segment
		(start 205.46568 10.56767)
		(end 207.047592 10.289032)
		(width 0.14732)
		(layer "In11.Cu")
		(net "DELTA_L_85_10INCH_IN4_DP")
	)
	(segment
		(start 195.456048 10.089134)
		(end 194.314826 3.615944)
		(width 0.14732)
		(layer "In11.Cu")
		(net "DELTA_L_85_10INCH_IN4_DP")
	)
	(segment
		(start 190.483998 3.481832)
		(end 191.84239 3.24231)
		(width 0.14732)
		(layer "In11.Cu")
		(net "DELTA_L_85_10INCH_IN4_DP")
	)
	(segment
		(start 211.62518 3.24485)
		(end 211.79536 3.36423)
		(width 0.14732)
		(layer "In11.Cu")
		(net "DELTA_L_85_10INCH_IN4_DP")
	)
	(segment
		(start 203.36383 10.058654)
		(end 202.23607 3.662934)
		(width 0.14732)
		(layer "In11.Cu")
		(net "DELTA_L_85_10INCH_IN4_DP")
	)
	(segment
		(start 201.174604 10.444734)
		(end 201.531728 10.694416)
		(width 0.14732)
		(layer "In11.Cu")
		(net "DELTA_L_85_10INCH_IN4_DP")
	)
	(segment
		(start 190.364618 3.652266)
		(end 190.483998 3.481832)
		(width 0.14732)
		(layer "In11.Cu")
		(net "DELTA_L_85_10INCH_IN4_DP")
	)
	(segment
		(start 188.47435 5.73151)
		(end 189.30874 10.464546)
		(width 0.14732)
		(layer "In11.Cu")
		(net "DELTA_L_85_10INCH_IN4_DP")
	)
	(segment
		(start 236.69244 9.929368)
		(end 237.048548 10.179304)
		(width 0.14732)
		(layer "In11.Cu")
		(net "DELTA_L_85_10INCH_IN4_DP")
	)
	(segment
		(start 203.884022 3.372358)
		(end 205.108556 10.317988)
		(width 0.14732)
		(layer "In11.Cu")
		(net "DELTA_L_85_10INCH_IN4_DP")
	)
	(segment
		(start 227.463858 3.318764)
		(end 227.634546 3.438652)
		(width 0.14732)
		(layer "In11.Cu")
		(net "DELTA_L_85_10INCH_IN4_DP")
	)
	(segment
		(start 222.138494 3.49885)
		(end 223.496886 3.259074)
		(width 0.14732)
		(layer "In11.Cu")
		(net "DELTA_L_85_10INCH_IN4_DP")
	)
	(segment
		(start 230.05542 3.519932)
		(end 230.05542 3.520186)
		(width 0.14732)
		(layer "In11.Cu")
		(net "DELTA_L_85_10INCH_IN4_DP")
	)
	(segment
		(start 183.652414 5.8928)
		(end 183.947054 5.59816)
		(width 0.14732)
		(layer "In11.Cu")
		(net "DELTA_L_85_10INCH_IN4_DP")
	)
	(segment
		(start 217.27414 10.22223)
		(end 218.856052 9.943084)
		(width 0.14732)
		(layer "In11.Cu")
		(net "DELTA_L_85_10INCH_IN4_DP")
	)
	(segment
		(start 231.413812 3.28041)
		(end 231.5845 3.400044)
		(width 0.14732)
		(layer "In11.Cu")
		(net "DELTA_L_85_10INCH_IN4_DP")
	)
	(segment
		(start 225.986086 3.72872)
		(end 226.105466 3.558286)
		(width 0.14732)
		(layer "In11.Cu")
		(net "DELTA_L_85_10INCH_IN4_DP")
	)
	(segment
		(start 191.84239 3.24231)
		(end 192.01257 3.36169)
		(width 0.14732)
		(layer "In11.Cu")
		(net "DELTA_L_85_10INCH_IN4_DP")
	)
	(segment
		(start 202.23607 3.662934)
		(end 202.35545 3.492754)
		(width 0.14732)
		(layer "In11.Cu")
		(net "DELTA_L_85_10INCH_IN4_DP")
	)
	(segment
		(start 223.069404 9.625076)
		(end 222.019114 3.669284)
		(width 0.14732)
		(layer "In11.Cu")
		(net "DELTA_L_85_10INCH_IN4_DP")
	)
	(segment
		(start 233.102912 10.239756)
		(end 234.685078 9.960356)
		(width 0.14732)
		(layer "In11.Cu")
		(net "DELTA_L_85_10INCH_IN4_DP")
	)
	(segment
		(start 218.194382 3.566668)
		(end 219.552774 3.326892)
		(width 0.14732)
		(layer "In11.Cu")
		(net "DELTA_L_85_10INCH_IN4_DP")
	)
	(segment
		(start 223.667828 3.378454)
		(end 224.826576 9.949942)
		(width 0.14732)
		(layer "In11.Cu")
		(net "DELTA_L_85_10INCH_IN4_DP")
	)
	(segment
		(start 210.147408 3.654806)
		(end 210.266788 3.484372)
		(width 0.14732)
		(layer "In11.Cu")
		(net "DELTA_L_85_10INCH_IN4_DP")
	)
	(segment
		(start 214.231982 3.533902)
		(end 215.590374 3.29438)
		(width 0.14732)
		(layer "In11.Cu")
		(net "DELTA_L_85_10INCH_IN4_DP")
	)
	(segment
		(start 218.194382 3.566414)
		(end 218.194382 3.566668)
		(width 0.14732)
		(layer "In11.Cu")
		(net "DELTA_L_85_10INCH_IN4_DP")
	)
	(segment
		(start 229.140512 10.207244)
		(end 230.722932 9.928098)
		(width 0.14732)
		(layer "In11.Cu")
		(net "DELTA_L_85_10INCH_IN4_DP")
	)
	(segment
		(start 194.434206 3.44551)
		(end 195.792598 3.205988)
		(width 0.14732)
		(layer "In11.Cu")
		(net "DELTA_L_85_10INCH_IN4_DP")
	)
	(segment
		(start 219.106242 9.586468)
		(end 218.075002 3.737356)
		(width 0.14732)
		(layer "In11.Cu")
		(net "DELTA_L_85_10INCH_IN4_DP")
	)
	(segment
		(start 191.497712 10.079228)
		(end 190.364618 3.652266)
		(width 0.14732)
		(layer "In11.Cu")
		(net "DELTA_L_85_10INCH_IN4_DP")
	)
	(segment
		(start 195.205858 10.44575)
		(end 195.456048 10.089134)
		(width 0.14732)
		(layer "In11.Cu")
		(net "DELTA_L_85_10INCH_IN4_DP")
	)
	(segment
		(start 211.008722 10.315194)
		(end 211.258658 9.957816)
		(width 0.14732)
		(layer "In11.Cu")
		(net "DELTA_L_85_10INCH_IN4_DP")
	)
	(segment
		(start 209.069686 10.343896)
		(end 209.426302 10.594086)
		(width 0.14732)
		(layer "In11.Cu")
		(net "DELTA_L_85_10INCH_IN4_DP")
	)
	(segment
		(start 224.826576 9.949942)
		(end 225.182684 10.199878)
		(width 0.14732)
		(layer "In11.Cu")
		(net "DELTA_L_85_10INCH_IN4_DP")
	)
	(segment
		(start 209.426302 10.594086)
		(end 211.008722 10.315194)
		(width 0.14732)
		(layer "In11.Cu")
		(net "DELTA_L_85_10INCH_IN4_DP")
	)
	(segment
		(start 237.048548 10.179304)
		(end 238.631222 9.900666)
		(width 0.14732)
		(layer "In11.Cu")
		(net "DELTA_L_85_10INCH_IN4_DP")
	)
	(segment
		(start 239.320324 3.244088)
		(end 239.491012 3.363468)
		(width 0.14732)
		(layer "In11.Cu")
		(net "DELTA_L_85_10INCH_IN4_DP")
	)
	(segment
		(start 203.713842 3.252978)
		(end 203.884022 3.372358)
		(width 0.14732)
		(layer "In11.Cu")
		(net "DELTA_L_85_10INCH_IN4_DP")
	)
	(segment
		(start 215.590374 3.29438)
		(end 215.760554 3.41376)
		(width 0.14732)
		(layer "In11.Cu")
		(net "DELTA_L_85_10INCH_IN4_DP")
	)
	(segment
		(start 235.37672 3.317494)
		(end 235.547662 3.436874)
		(width 0.14732)
		(layer "In11.Cu")
		(net "DELTA_L_85_10INCH_IN4_DP")
	)
	(segment
		(start 198.408036 3.543808)
		(end 199.766428 3.304032)
		(width 0.14732)
		(layer "In11.Cu")
		(net "DELTA_L_85_10INCH_IN4_DP")
	)
	(segment
		(start 199.766428 3.304032)
		(end 199.936608 3.423412)
		(width 0.14732)
		(layer "In11.Cu")
		(net "DELTA_L_85_10INCH_IN4_DP")
	)
	(segment
		(start 214.902288 9.958324)
		(end 215.152478 9.601708)
		(width 0.14732)
		(layer "In11.Cu")
		(net "DELTA_L_85_10INCH_IN4_DP")
	)
	(segment
		(start 244.106446 5.59816)
		(end 248.853706 5.59816)
		(width 0.14732)
		(layer "In11.Cu")
		(net "DELTA_L_85_10INCH_IN4_DP")
	)
	(segment
		(start 194.314826 3.615944)
		(end 194.434206 3.44551)
		(width 0.14732)
		(layer "In11.Cu")
		(net "DELTA_L_85_10INCH_IN4_DP")
	)
	(segment
		(start 188.3156 5.59816)
		(end 188.47435 5.73151)
		(width 0.14732)
		(layer "In11.Cu")
		(net "DELTA_L_85_10INCH_IN4_DP")
	)
	(segment
		(start 248.853706 5.59816)
		(end 249.148346 5.8928)
		(width 0.14732)
		(layer "In11.Cu")
		(net "DELTA_L_85_10INCH_IN4_DP")
	)
	(segment
		(start 239.491012 3.363468)
		(end 240.647728 9.923272)
		(width 0.14732)
		(layer "In11.Cu")
		(net "DELTA_L_85_10INCH_IN4_DP")
	)
	(segment
		(start 213.320122 10.23747)
		(end 214.902288 9.958324)
		(width 0.14732)
		(layer "In11.Cu")
		(net "DELTA_L_85_10INCH_IN4_DP")
	)
	(segment
		(start 234.685078 9.960356)
		(end 234.935014 9.604248)
		(width 0.14732)
		(layer "In11.Cu")
		(net "DELTA_L_85_10INCH_IN4_DP")
	)
	(segment
		(start 243.455952 3.41376)
		(end 243.794788 5.33654)
		(width 0.14732)
		(layer "In11.Cu")
		(net "DELTA_L_85_10INCH_IN4_DP")
	)
	(segment
		(start 193.267076 10.474452)
		(end 193.623692 10.724642)
		(width 0.14732)
		(layer "In11.Cu")
		(net "DELTA_L_85_10INCH_IN4_DP")
	)
	(segment
		(start 221.237302 10.260838)
		(end 222.819722 9.9822)
		(width 0.14732)
		(layer "In11.Cu")
		(net "DELTA_L_85_10INCH_IN4_DP")
	)
	(segment
		(start 234.018328 3.55727)
		(end 235.37672 3.317494)
		(width 0.14732)
		(layer "In11.Cu")
		(net "DELTA_L_85_10INCH_IN4_DP")
	)
	(segment
		(start 223.496886 3.259074)
		(end 223.667828 3.378454)
		(width 0.14732)
		(layer "In11.Cu")
		(net "DELTA_L_85_10INCH_IN4_DP")
	)
	(segment
		(start 212.963506 9.98728)
		(end 213.320122 10.23747)
		(width 0.14732)
		(layer "In11.Cu")
		(net "DELTA_L_85_10INCH_IN4_DP")
	)
	(segment
		(start 191.247522 10.435844)
		(end 191.497712 10.079228)
		(width 0.14732)
		(layer "In11.Cu")
		(net "DELTA_L_85_10INCH_IN4_DP")
	)
	(segment
		(start 242.836192 9.5377)
		(end 241.807746 3.704082)
		(width 0.14732)
		(layer "In11.Cu")
		(net "DELTA_L_85_10INCH_IN4_DP")
	)
	(segment
		(start 195.792598 3.205988)
		(end 195.962778 3.325368)
		(width 0.14732)
		(layer "In11.Cu")
		(net "DELTA_L_85_10INCH_IN4_DP")
	)
	(segment
		(start 207.847184 3.40995)
		(end 209.069686 10.343896)
		(width 0.14732)
		(layer "In11.Cu")
		(net "DELTA_L_85_10INCH_IN4_DP")
	)
	(segment
		(start 199.404732 10.046208)
		(end 198.288656 3.714242)
		(width 0.14732)
		(layer "In11.Cu")
		(net "DELTA_L_85_10INCH_IN4_DP")
	)
	(segment
		(start 206.199232 3.70078)
		(end 206.318612 3.530346)
		(width 0.14732)
		(layer "In11.Cu")
		(net "DELTA_L_85_10INCH_IN4_DP")
	)
	(segment
		(start 229.93604 3.690874)
		(end 230.05542 3.519932)
		(width 0.14732)
		(layer "In11.Cu")
		(net "DELTA_L_85_10INCH_IN4_DP")
	)
	(segment
		(start 243.794788 5.33654)
		(end 244.106446 5.59816)
		(width 0.14732)
		(layer "In11.Cu")
		(net "DELTA_L_85_10INCH_IN4_DP")
	)
	(segment
		(start 201.531728 10.694416)
		(end 203.11364 10.41527)
		(width 0.14732)
		(layer "In11.Cu")
		(net "DELTA_L_85_10INCH_IN4_DP")
	)
	(segment
		(start 199.154542 10.402824)
		(end 199.404732 10.046208)
		(width 0.14732)
		(layer "In11.Cu")
		(net "DELTA_L_85_10INCH_IN4_DP")
	)
	(segment
		(start 230.972868 9.57199)
		(end 229.93604 3.690874)
		(width 0.14732)
		(layer "In11.Cu")
		(net "DELTA_L_85_10INCH_IN4_DP")
	)
	(segment
		(start 207.297782 9.932416)
		(end 206.199232 3.70078)
		(width 0.14732)
		(layer "In11.Cu")
		(net "DELTA_L_85_10INCH_IN4_DP")
	)
	(segment
		(start 192.01257 3.36169)
		(end 193.267076 10.474452)
		(width 0.14732)
		(layer "In11.Cu")
		(net "DELTA_L_85_10INCH_IN4_DP")
	)
	(segment
		(start 202.35545 3.492754)
		(end 203.713842 3.252978)
		(width 0.14732)
		(layer "In11.Cu")
		(net "DELTA_L_85_10INCH_IN4_DP")
	)
	(segment
		(start 197.57263 10.68197)
		(end 199.154542 10.402824)
		(width 0.14732)
		(layer "In11.Cu")
		(net "DELTA_L_85_10INCH_IN4_DP")
	)
	(segment
		(start 207.67675 3.29057)
		(end 207.847184 3.40995)
		(width 0.14732)
		(layer "In11.Cu")
		(net "DELTA_L_85_10INCH_IN4_DP")
	)
	(segment
		(start 218.856052 9.943084)
		(end 219.106242 9.586468)
		(width 0.14732)
		(layer "In11.Cu")
		(net "DELTA_L_85_10INCH_IN4_DP")
	)
	(segment
		(start 222.819722 9.9822)
		(end 223.069404 9.625076)
		(width 0.14732)
		(layer "In11.Cu")
		(net "DELTA_L_85_10INCH_IN4_DP")
	)
	(segment
		(start 193.623692 10.724642)
		(end 195.205858 10.44575)
		(width 0.14732)
		(layer "In11.Cu")
		(net "DELTA_L_85_10INCH_IN4_DP")
	)
	(segment
		(start 240.647728 9.923272)
		(end 241.00409 10.173208)
		(width 0.14732)
		(layer "In11.Cu")
		(net "DELTA_L_85_10INCH_IN4_DP")
	)
	(segment
		(start 225.182684 10.199878)
		(end 226.765104 9.920732)
		(width 0.14732)
		(layer "In11.Cu")
		(net "DELTA_L_85_10INCH_IN4_DP")
	)
	(segment
		(start 238.631222 9.900666)
		(end 238.880904 9.543542)
		(width 0.14732)
		(layer "In11.Cu")
		(net "DELTA_L_85_10INCH_IN4_DP")
	)
	(segment
		(start 197.215506 10.432288)
		(end 197.57263 10.68197)
		(width 0.14732)
		(layer "In11.Cu")
		(net "DELTA_L_85_10INCH_IN4_DP")
	)
	(segment
		(start 226.765104 9.920732)
		(end 227.01504 9.564624)
		(width 0.14732)
		(layer "In11.Cu")
		(net "DELTA_L_85_10INCH_IN4_DP")
	)
	(segment
		(start 227.634546 3.438652)
		(end 228.784404 9.957308)
		(width 0.14732)
		(layer "In11.Cu")
		(net "DELTA_L_85_10INCH_IN4_DP")
	)
	(segment
		(start 195.962778 3.325368)
		(end 197.215506 10.432288)
		(width 0.14732)
		(layer "In11.Cu")
		(net "DELTA_L_85_10INCH_IN4_DP")
	)
	(segment
		(start 231.5845 3.400044)
		(end 232.746296 9.98982)
		(width 0.14732)
		(layer "In11.Cu")
		(net "DELTA_L_85_10INCH_IN4_DP")
	)
	(segment
		(start 206.318612 3.530346)
		(end 207.67675 3.29057)
		(width 0.14732)
		(layer "In11.Cu")
		(net "DELTA_L_85_10INCH_IN4_DP")
	)
	(segment
		(start 220.880686 10.010902)
		(end 221.237302 10.260838)
		(width 0.14732)
		(layer "In11.Cu")
		(net "DELTA_L_85_10INCH_IN4_DP")
	)
	(segment
		(start 242.586764 9.89457)
		(end 242.836192 9.5377)
		(width 0.14732)
		(layer "In11.Cu")
		(net "DELTA_L_85_10INCH_IN4_DP")
	)
	(segment
		(start 205.108556 10.317988)
		(end 205.46568 10.56767)
		(width 0.14732)
		(layer "In11.Cu")
		(net "DELTA_L_85_10INCH_IN4_DP")
	)
	(segment
		(start 216.917524 9.972294)
		(end 217.27414 10.22223)
		(width 0.14732)
		(layer "In11.Cu")
		(net "DELTA_L_85_10INCH_IN4_DP")
	)
	(segment
		(start 203.11364 10.41527)
		(end 203.36383 10.058654)
		(width 0.14732)
		(layer "In11.Cu")
		(net "DELTA_L_85_10INCH_IN4_DP")
	)
	(segment
		(start 211.79536 3.36423)
		(end 212.963506 9.98728)
		(width 0.14732)
		(layer "In11.Cu")
		(net "DELTA_L_85_10INCH_IN4_DP")
	)
	(segment
		(start 228.784404 9.957308)
		(end 229.140512 10.207244)
		(width 0.14732)
		(layer "In11.Cu")
		(net "DELTA_L_85_10INCH_IN4_DP")
	)
	(segment
		(start 234.935014 9.604248)
		(end 233.898948 3.727704)
		(width 0.14732)
		(layer "In11.Cu")
		(net "DELTA_L_85_10INCH_IN4_DP")
	)
	(segment
		(start 227.01504 9.564624)
		(end 225.986086 3.72872)
		(width 0.14732)
		(layer "In11.Cu")
		(net "DELTA_L_85_10INCH_IN4_DP")
	)
	(segment
		(start 219.722954 3.446018)
		(end 220.880686 10.010902)
		(width 0.14732)
		(layer "In11.Cu")
		(net "DELTA_L_85_10INCH_IN4_DP")
	)
	(segment
		(start 215.152478 9.601708)
		(end 214.112602 3.704336)
		(width 0.14732)
		(layer "In11.Cu")
		(net "DELTA_L_85_10INCH_IN4_DP")
	)
	(segment
		(start 226.105466 3.558286)
		(end 227.463858 3.318764)
		(width 0.14732)
		(layer "In11.Cu")
		(net "DELTA_L_85_10INCH_IN4_DP")
	)
	(segment
		(start 210.266788 3.484372)
		(end 211.62518 3.24485)
		(width 0.14732)
		(layer "In11.Cu")
		(net "DELTA_L_85_10INCH_IN4_DP")
	)
	(segment
		(start 222.138494 3.498596)
		(end 222.138494 3.49885)
		(width 0.14732)
		(layer "In11.Cu")
		(net "DELTA_L_85_10INCH_IN4_DP")
	)
	(segment
		(start 243.285264 3.29438)
		(end 243.455952 3.41376)
		(width 0.14732)
		(layer "In11.Cu")
		(net "DELTA_L_85_10INCH_IN4_DP")
	)
	(segment
		(start 219.552774 3.326892)
		(end 219.722954 3.446018)
		(width 0.14732)
		(layer "In11.Cu")
		(net "DELTA_L_85_10INCH_IN4_DP")
	)
	(segment
		(start 232.746296 9.98982)
		(end 233.102912 10.239756)
		(width 0.14732)
		(layer "In11.Cu")
		(net "DELTA_L_85_10INCH_IN4_DP")
	)
	(segment
		(start 233.898948 3.727704)
		(end 234.018328 3.55727)
		(width 0.14732)
		(layer "In11.Cu")
		(net "DELTA_L_85_10INCH_IN4_DP")
	)
	(segment
		(start 241.807746 3.704082)
		(end 241.926872 3.533902)
		(width 0.14732)
		(layer "In11.Cu")
		(net "DELTA_L_85_10INCH_IN4_DP")
	)
	(segment
		(start 230.722932 9.928098)
		(end 230.972868 9.57199)
		(width 0.14732)
		(layer "In11.Cu")
		(net "DELTA_L_85_10INCH_IN4_DP")
	)
	(segment
		(start 222.019114 3.669284)
		(end 222.138494 3.498596)
		(width 0.14732)
		(layer "In11.Cu")
		(net "DELTA_L_85_10INCH_IN4_DP")
	)
	(segment
		(start 207.047592 10.289032)
		(end 207.297782 9.932416)
		(width 0.14732)
		(layer "In11.Cu")
		(net "DELTA_L_85_10INCH_IN4_DP")
	)
	(segment
		(start 211.258658 9.957816)
		(end 210.147408 3.654806)
		(width 0.14732)
		(layer "In11.Cu")
		(net "DELTA_L_85_10INCH_IN4_DP")
	)
	(segment
		(start 241.00409 10.173208)
		(end 242.586764 9.89457)
		(width 0.14732)
		(layer "In11.Cu")
		(net "DELTA_L_85_10INCH_IN4_DP")
	)
	(segment
		(start 183.947054 5.59816)
		(end 188.3156 5.59816)
		(width 0.14732)
		(layer "In11.Cu")
		(net "DELTA_L_85_10INCH_IN4_DP")
	)
	(segment
		(start 235.547662 3.436874)
		(end 236.69244 9.929368)
		(width 0.14732)
		(layer "In11.Cu")
		(net "DELTA_L_85_10INCH_IN4_DP")
	)
	(segment
		(start 237.842552 3.654298)
		(end 237.961678 3.48361)
		(width 0.14732)
		(layer "In11.Cu")
		(net "DELTA_L_85_10INCH_IN4_DP")
	)
	(segment
		(start 214.112602 3.704336)
		(end 214.231982 3.533902)
		(width 0.14732)
		(layer "In11.Cu")
		(net "DELTA_L_85_10INCH_IN4_DP")
	)
	(segment
		(start 237.961678 3.48361)
		(end 239.320324 3.244088)
		(width 0.14732)
		(layer "In11.Cu")
		(net "DELTA_L_85_10INCH_IN4_DP")
	)
	(segment
		(start 215.760554 3.41376)
		(end 216.917524 9.972294)
		(width 0.14732)
		(layer "In11.Cu")
		(net "DELTA_L_85_10INCH_IN4_DP")
	)
	(segment
		(start 182.97144 5.211064)
		(end 183.652414 5.0292)
		(width 0.13208)
		(layer "B.Cu")
		(net "DELTA_L_85_10INCH_IN4_DN")
	)
	(segment
		(start 249.82932 5.211064)
		(end 249.148346 5.0292)
		(width 0.13208)
		(layer "B.Cu")
		(net "DELTA_L_85_10INCH_IN4_DN")
	)
	(segment
		(start 237.552484 3.589528)
		(end 237.802166 3.233166)
		(width 0.14732)
		(layer "In11.Cu")
		(net "DELTA_L_85_10INCH_IN4_DN")
	)
	(segment
		(start 218.816174 9.521952)
		(end 217.784934 3.67284)
		(width 0.14732)
		(layer "In11.Cu")
		(net "DELTA_L_85_10INCH_IN4_DN")
	)
	(segment
		(start 216.011252 3.253994)
		(end 217.167968 9.812782)
		(width 0.14732)
		(layer "In11.Cu")
		(net "DELTA_L_85_10INCH_IN4_DN")
	)
	(segment
		(start 209.85734 3.59029)
		(end 210.107022 3.233674)
		(width 0.14732)
		(layer "In11.Cu")
		(net "DELTA_L_85_10INCH_IN4_DN")
	)
	(segment
		(start 210.96859 9.893554)
		(end 209.85734 3.59029)
		(width 0.14732)
		(layer "In11.Cu")
		(net "DELTA_L_85_10INCH_IN4_DN")
	)
	(segment
		(start 235.798106 3.277108)
		(end 236.942884 9.769856)
		(width 0.14732)
		(layer "In11.Cu")
		(net "DELTA_L_85_10INCH_IN4_DN")
	)
	(segment
		(start 240.898172 9.76376)
		(end 241.068606 9.88314)
		(width 0.14732)
		(layer "In11.Cu")
		(net "DELTA_L_85_10INCH_IN4_DN")
	)
	(segment
		(start 205.529942 10.277602)
		(end 206.88808 10.038334)
		(width 0.14732)
		(layer "In11.Cu")
		(net "DELTA_L_85_10INCH_IN4_DN")
	)
	(segment
		(start 233.858562 3.306572)
		(end 235.440982 3.027426)
		(width 0.14732)
		(layer "In11.Cu")
		(net "DELTA_L_85_10INCH_IN4_DN")
	)
	(segment
		(start 237.113064 9.889236)
		(end 238.471456 9.649968)
		(width 0.14732)
		(layer "In11.Cu")
		(net "DELTA_L_85_10INCH_IN4_DN")
	)
	(segment
		(start 201.425302 10.284968)
		(end 201.59599 10.404348)
		(width 0.14732)
		(layer "In11.Cu")
		(net "DELTA_L_85_10INCH_IN4_DN")
	)
	(segment
		(start 234.644946 9.539732)
		(end 233.60888 3.663188)
		(width 0.14732)
		(layer "In11.Cu")
		(net "DELTA_L_85_10INCH_IN4_DN")
	)
	(segment
		(start 193.51752 10.31494)
		(end 193.688208 10.434574)
		(width 0.14732)
		(layer "In11.Cu")
		(net "DELTA_L_85_10INCH_IN4_DN")
	)
	(segment
		(start 233.167174 9.949688)
		(end 234.525566 9.709912)
		(width 0.14732)
		(layer "In11.Cu")
		(net "DELTA_L_85_10INCH_IN4_DN")
	)
	(segment
		(start 229.895654 3.269488)
		(end 231.478328 2.990342)
		(width 0.14732)
		(layer "In11.Cu")
		(net "DELTA_L_85_10INCH_IN4_DN")
	)
	(segment
		(start 211.689442 2.954782)
		(end 212.046058 3.204464)
		(width 0.14732)
		(layer "In11.Cu")
		(net "DELTA_L_85_10INCH_IN4_DN")
	)
	(segment
		(start 212.046058 3.204464)
		(end 213.21395 9.827768)
		(width 0.14732)
		(layer "In11.Cu")
		(net "DELTA_L_85_10INCH_IN4_DN")
	)
	(segment
		(start 208.097628 3.250438)
		(end 209.320384 10.184384)
		(width 0.14732)
		(layer "In11.Cu")
		(net "DELTA_L_85_10INCH_IN4_DN")
	)
	(segment
		(start 202.195684 3.242056)
		(end 203.778104 2.96291)
		(width 0.14732)
		(layer "In11.Cu")
		(net "DELTA_L_85_10INCH_IN4_DN")
	)
	(segment
		(start 217.338402 9.932162)
		(end 218.69654 9.69264)
		(width 0.14732)
		(layer "In11.Cu")
		(net "DELTA_L_85_10INCH_IN4_DN")
	)
	(segment
		(start 210.848956 10.064496)
		(end 210.96859 9.893554)
		(width 0.14732)
		(layer "In11.Cu")
		(net "DELTA_L_85_10INCH_IN4_DN")
	)
	(segment
		(start 188.727334 5.58546)
		(end 189.559184 10.305034)
		(width 0.14732)
		(layer "In11.Cu")
		(net "DELTA_L_85_10INCH_IN4_DN")
	)
	(segment
		(start 223.918272 3.218688)
		(end 225.07702 9.79043)
		(width 0.14732)
		(layer "In11.Cu")
		(net "DELTA_L_85_10INCH_IN4_DN")
	)
	(segment
		(start 233.60888 3.663188)
		(end 233.858562 3.306572)
		(width 0.14732)
		(layer "In11.Cu")
		(net "DELTA_L_85_10INCH_IN4_DN")
	)
	(segment
		(start 214.072216 3.283204)
		(end 215.654636 3.004312)
		(width 0.14732)
		(layer "In11.Cu")
		(net "DELTA_L_85_10INCH_IN4_DN")
	)
	(segment
		(start 244.047772 5.19049)
		(end 244.206522 5.32384)
		(width 0.14732)
		(layer "In11.Cu")
		(net "DELTA_L_85_10INCH_IN4_DN")
	)
	(segment
		(start 232.99674 9.830308)
		(end 233.167174 9.949688)
		(width 0.14732)
		(layer "In11.Cu")
		(net "DELTA_L_85_10INCH_IN4_DN")
	)
	(segment
		(start 221.301564 9.97077)
		(end 222.659956 9.731502)
		(width 0.14732)
		(layer "In11.Cu")
		(net "DELTA_L_85_10INCH_IN4_DN")
	)
	(segment
		(start 190.324232 3.231134)
		(end 191.906652 2.952242)
		(width 0.14732)
		(layer "In11.Cu")
		(net "DELTA_L_85_10INCH_IN4_DN")
	)
	(segment
		(start 197.636892 10.391902)
		(end 198.99503 10.15238)
		(width 0.14732)
		(layer "In11.Cu")
		(net "DELTA_L_85_10INCH_IN4_DN")
	)
	(segment
		(start 214.742776 9.70788)
		(end 214.86241 9.537192)
		(width 0.14732)
		(layer "In11.Cu")
		(net "DELTA_L_85_10INCH_IN4_DN")
	)
	(segment
		(start 206.88808 10.038334)
		(end 207.007714 9.8679)
		(width 0.14732)
		(layer "In11.Cu")
		(net "DELTA_L_85_10INCH_IN4_DN")
	)
	(segment
		(start 238.590836 9.47928)
		(end 237.552484 3.589528)
		(width 0.14732)
		(layer "In11.Cu")
		(net "DELTA_L_85_10INCH_IN4_DN")
	)
	(segment
		(start 188.415422 5.32384)
		(end 188.727334 5.58546)
		(width 0.14732)
		(layer "In11.Cu")
		(net "DELTA_L_85_10INCH_IN4_DN")
	)
	(segment
		(start 231.478328 2.990342)
		(end 231.834944 3.240532)
		(width 0.14732)
		(layer "In11.Cu")
		(net "DELTA_L_85_10INCH_IN4_DN")
	)
	(segment
		(start 206.158846 3.279648)
		(end 207.741266 3.000502)
		(width 0.14732)
		(layer "In11.Cu")
		(net "DELTA_L_85_10INCH_IN4_DN")
	)
	(segment
		(start 191.08801 10.185146)
		(end 191.207644 10.014712)
		(width 0.14732)
		(layer "In11.Cu")
		(net "DELTA_L_85_10INCH_IN4_DN")
	)
	(segment
		(start 243.349526 3.004312)
		(end 243.70665 3.253994)
		(width 0.14732)
		(layer "In11.Cu")
		(net "DELTA_L_85_10INCH_IN4_DN")
	)
	(segment
		(start 209.320384 10.184384)
		(end 209.490818 10.304018)
		(width 0.14732)
		(layer "In11.Cu")
		(net "DELTA_L_85_10INCH_IN4_DN")
	)
	(segment
		(start 217.167968 9.812782)
		(end 217.338402 9.932162)
		(width 0.14732)
		(layer "In11.Cu")
		(net "DELTA_L_85_10INCH_IN4_DN")
	)
	(segment
		(start 183.652414 5.0292)
		(end 183.947054 5.32384)
		(width 0.14732)
		(layer "In11.Cu")
		(net "DELTA_L_85_10INCH_IN4_DN")
	)
	(segment
		(start 203.778104 2.96291)
		(end 204.13472 3.212592)
		(width 0.14732)
		(layer "In11.Cu")
		(net "DELTA_L_85_10INCH_IN4_DN")
	)
	(segment
		(start 229.645972 3.626612)
		(end 229.895654 3.269488)
		(width 0.14732)
		(layer "In11.Cu")
		(net "DELTA_L_85_10INCH_IN4_DN")
	)
	(segment
		(start 243.70665 3.253994)
		(end 244.047772 5.19049)
		(width 0.14732)
		(layer "In11.Cu")
		(net "DELTA_L_85_10INCH_IN4_DN")
	)
	(segment
		(start 207.007714 9.8679)
		(end 205.909164 3.636264)
		(width 0.14732)
		(layer "In11.Cu")
		(net "DELTA_L_85_10INCH_IN4_DN")
	)
	(segment
		(start 190.07455 3.58775)
		(end 190.324232 3.231134)
		(width 0.14732)
		(layer "In11.Cu")
		(net "DELTA_L_85_10INCH_IN4_DN")
	)
	(segment
		(start 214.86241 9.537192)
		(end 213.822534 3.640074)
		(width 0.14732)
		(layer "In11.Cu")
		(net "DELTA_L_85_10INCH_IN4_DN")
	)
	(segment
		(start 217.784934 3.67284)
		(end 218.03487 3.31597)
		(width 0.14732)
		(layer "In11.Cu")
		(net "DELTA_L_85_10INCH_IN4_DN")
	)
	(segment
		(start 202.954128 10.164826)
		(end 203.073762 9.994138)
		(width 0.14732)
		(layer "In11.Cu")
		(net "DELTA_L_85_10INCH_IN4_DN")
	)
	(segment
		(start 222.659956 9.731502)
		(end 222.779336 9.560814)
		(width 0.14732)
		(layer "In11.Cu")
		(net "DELTA_L_85_10INCH_IN4_DN")
	)
	(segment
		(start 205.909164 3.636264)
		(end 206.158846 3.279648)
		(width 0.14732)
		(layer "In11.Cu")
		(net "DELTA_L_85_10INCH_IN4_DN")
	)
	(segment
		(start 199.83069 3.013964)
		(end 200.187306 3.263646)
		(width 0.14732)
		(layer "In11.Cu")
		(net "DELTA_L_85_10INCH_IN4_DN")
	)
	(segment
		(start 244.206522 5.32384)
		(end 248.853706 5.32384)
		(width 0.14732)
		(layer "In11.Cu")
		(net "DELTA_L_85_10INCH_IN4_DN")
	)
	(segment
		(start 236.942884 9.769856)
		(end 237.113064 9.889236)
		(width 0.14732)
		(layer "In11.Cu")
		(net "DELTA_L_85_10INCH_IN4_DN")
	)
	(segment
		(start 198.24827 3.29311)
		(end 199.83069 3.013964)
		(width 0.14732)
		(layer "In11.Cu")
		(net "DELTA_L_85_10INCH_IN4_DN")
	)
	(segment
		(start 237.802166 3.233166)
		(end 239.384586 2.95402)
		(width 0.14732)
		(layer "In11.Cu")
		(net "DELTA_L_85_10INCH_IN4_DN")
	)
	(segment
		(start 195.16598 10.024618)
		(end 194.024758 3.551428)
		(width 0.14732)
		(layer "In11.Cu")
		(net "DELTA_L_85_10INCH_IN4_DN")
	)
	(segment
		(start 213.822534 3.640074)
		(end 214.072216 3.283204)
		(width 0.14732)
		(layer "In11.Cu")
		(net "DELTA_L_85_10INCH_IN4_DN")
	)
	(segment
		(start 213.384638 9.947402)
		(end 214.742776 9.70788)
		(width 0.14732)
		(layer "In11.Cu")
		(net "DELTA_L_85_10INCH_IN4_DN")
	)
	(segment
		(start 203.073762 9.994138)
		(end 201.946002 3.598672)
		(width 0.14732)
		(layer "In11.Cu")
		(net "DELTA_L_85_10INCH_IN4_DN")
	)
	(segment
		(start 226.605592 9.670288)
		(end 226.724972 9.500108)
		(width 0.14732)
		(layer "In11.Cu")
		(net "DELTA_L_85_10INCH_IN4_DN")
	)
	(segment
		(start 225.07702 9.79043)
		(end 225.2472 9.90981)
		(width 0.14732)
		(layer "In11.Cu")
		(net "DELTA_L_85_10INCH_IN4_DN")
	)
	(segment
		(start 230.6828 9.507474)
		(end 229.645972 3.626612)
		(width 0.14732)
		(layer "In11.Cu")
		(net "DELTA_L_85_10INCH_IN4_DN")
	)
	(segment
		(start 241.517678 3.639566)
		(end 241.76736 3.283458)
		(width 0.14732)
		(layer "In11.Cu")
		(net "DELTA_L_85_10INCH_IN4_DN")
	)
	(segment
		(start 221.729046 3.604768)
		(end 221.978982 3.248152)
		(width 0.14732)
		(layer "In11.Cu")
		(net "DELTA_L_85_10INCH_IN4_DN")
	)
	(segment
		(start 201.946002 3.598672)
		(end 202.195684 3.242056)
		(width 0.14732)
		(layer "In11.Cu")
		(net "DELTA_L_85_10INCH_IN4_DN")
	)
	(segment
		(start 227.885244 3.27914)
		(end 229.034848 9.797796)
		(width 0.14732)
		(layer "In11.Cu")
		(net "DELTA_L_85_10INCH_IN4_DN")
	)
	(segment
		(start 204.13472 3.212592)
		(end 205.359 10.158222)
		(width 0.14732)
		(layer "In11.Cu")
		(net "DELTA_L_85_10INCH_IN4_DN")
	)
	(segment
		(start 235.440982 3.027426)
		(end 235.798106 3.277108)
		(width 0.14732)
		(layer "In11.Cu")
		(net "DELTA_L_85_10INCH_IN4_DN")
	)
	(segment
		(start 219.617036 3.036824)
		(end 219.973398 3.286506)
		(width 0.14732)
		(layer "In11.Cu")
		(net "DELTA_L_85_10INCH_IN4_DN")
	)
	(segment
		(start 241.068606 9.88314)
		(end 242.426998 9.644126)
		(width 0.14732)
		(layer "In11.Cu")
		(net "DELTA_L_85_10INCH_IN4_DN")
	)
	(segment
		(start 191.207644 10.014712)
		(end 190.07455 3.58775)
		(width 0.14732)
		(layer "In11.Cu")
		(net "DELTA_L_85_10INCH_IN4_DN")
	)
	(segment
		(start 195.046346 10.195052)
		(end 195.16598 10.024618)
		(width 0.14732)
		(layer "In11.Cu")
		(net "DELTA_L_85_10INCH_IN4_DN")
	)
	(segment
		(start 219.973398 3.286506)
		(end 221.13113 9.85139)
		(width 0.14732)
		(layer "In11.Cu")
		(net "DELTA_L_85_10INCH_IN4_DN")
	)
	(segment
		(start 189.729872 10.424668)
		(end 191.08801 10.185146)
		(width 0.14732)
		(layer "In11.Cu")
		(net "DELTA_L_85_10INCH_IN4_DN")
	)
	(segment
		(start 221.13113 9.85139)
		(end 221.301564 9.97077)
		(width 0.14732)
		(layer "In11.Cu")
		(net "DELTA_L_85_10INCH_IN4_DN")
	)
	(segment
		(start 205.359 10.158222)
		(end 205.529942 10.277602)
		(width 0.14732)
		(layer "In11.Cu")
		(net "DELTA_L_85_10INCH_IN4_DN")
	)
	(segment
		(start 195.85686 2.91592)
		(end 196.213476 3.165602)
		(width 0.14732)
		(layer "In11.Cu")
		(net "DELTA_L_85_10INCH_IN4_DN")
	)
	(segment
		(start 210.107022 3.233674)
		(end 211.689442 2.954782)
		(width 0.14732)
		(layer "In11.Cu")
		(net "DELTA_L_85_10INCH_IN4_DN")
	)
	(segment
		(start 183.947054 5.32384)
		(end 188.415422 5.32384)
		(width 0.14732)
		(layer "In11.Cu")
		(net "DELTA_L_85_10INCH_IN4_DN")
	)
	(segment
		(start 221.978982 3.248152)
		(end 223.561148 2.969006)
		(width 0.14732)
		(layer "In11.Cu")
		(net "DELTA_L_85_10INCH_IN4_DN")
	)
	(segment
		(start 197.466204 10.272522)
		(end 197.636892 10.391902)
		(width 0.14732)
		(layer "In11.Cu")
		(net "DELTA_L_85_10INCH_IN4_DN")
	)
	(segment
		(start 248.853706 5.32384)
		(end 249.148346 5.0292)
		(width 0.14732)
		(layer "In11.Cu")
		(net "DELTA_L_85_10INCH_IN4_DN")
	)
	(segment
		(start 238.471456 9.649968)
		(end 238.590836 9.47928)
		(width 0.14732)
		(layer "In11.Cu")
		(net "DELTA_L_85_10INCH_IN4_DN")
	)
	(segment
		(start 193.688208 10.434574)
		(end 195.046346 10.195052)
		(width 0.14732)
		(layer "In11.Cu")
		(net "DELTA_L_85_10INCH_IN4_DN")
	)
	(segment
		(start 229.205028 9.917176)
		(end 230.56342 9.677654)
		(width 0.14732)
		(layer "In11.Cu")
		(net "DELTA_L_85_10INCH_IN4_DN")
	)
	(segment
		(start 230.56342 9.677654)
		(end 230.6828 9.507474)
		(width 0.14732)
		(layer "In11.Cu")
		(net "DELTA_L_85_10INCH_IN4_DN")
	)
	(segment
		(start 231.834944 3.240532)
		(end 232.99674 9.830308)
		(width 0.14732)
		(layer "In11.Cu")
		(net "DELTA_L_85_10INCH_IN4_DN")
	)
	(segment
		(start 222.779336 9.560814)
		(end 221.729046 3.604768)
		(width 0.14732)
		(layer "In11.Cu")
		(net "DELTA_L_85_10INCH_IN4_DN")
	)
	(segment
		(start 209.490818 10.304018)
		(end 210.848956 10.064496)
		(width 0.14732)
		(layer "In11.Cu")
		(net "DELTA_L_85_10INCH_IN4_DN")
	)
	(segment
		(start 242.426998 9.644126)
		(end 242.546124 9.473438)
		(width 0.14732)
		(layer "In11.Cu")
		(net "DELTA_L_85_10INCH_IN4_DN")
	)
	(segment
		(start 192.263268 3.201924)
		(end 193.51752 10.31494)
		(width 0.14732)
		(layer "In11.Cu")
		(net "DELTA_L_85_10INCH_IN4_DN")
	)
	(segment
		(start 189.559184 10.305034)
		(end 189.729872 10.424668)
		(width 0.14732)
		(layer "In11.Cu")
		(net "DELTA_L_85_10INCH_IN4_DN")
	)
	(segment
		(start 196.213476 3.165602)
		(end 197.466204 10.272522)
		(width 0.14732)
		(layer "In11.Cu")
		(net "DELTA_L_85_10INCH_IN4_DN")
	)
	(segment
		(start 191.906652 2.952242)
		(end 192.263268 3.201924)
		(width 0.14732)
		(layer "In11.Cu")
		(net "DELTA_L_85_10INCH_IN4_DN")
	)
	(segment
		(start 199.114664 9.981692)
		(end 197.998588 3.64998)
		(width 0.14732)
		(layer "In11.Cu")
		(net "DELTA_L_85_10INCH_IN4_DN")
	)
	(segment
		(start 198.99503 10.15238)
		(end 199.114664 9.981692)
		(width 0.14732)
		(layer "In11.Cu")
		(net "DELTA_L_85_10INCH_IN4_DN")
	)
	(segment
		(start 218.03487 3.31597)
		(end 219.617036 3.036824)
		(width 0.14732)
		(layer "In11.Cu")
		(net "DELTA_L_85_10INCH_IN4_DN")
	)
	(segment
		(start 241.76736 3.283458)
		(end 243.349526 3.004312)
		(width 0.14732)
		(layer "In11.Cu")
		(net "DELTA_L_85_10INCH_IN4_DN")
	)
	(segment
		(start 197.998588 3.64998)
		(end 198.24827 3.29311)
		(width 0.14732)
		(layer "In11.Cu")
		(net "DELTA_L_85_10INCH_IN4_DN")
	)
	(segment
		(start 194.024758 3.551428)
		(end 194.27444 3.194812)
		(width 0.14732)
		(layer "In11.Cu")
		(net "DELTA_L_85_10INCH_IN4_DN")
	)
	(segment
		(start 223.561148 2.969006)
		(end 223.918272 3.218688)
		(width 0.14732)
		(layer "In11.Cu")
		(net "DELTA_L_85_10INCH_IN4_DN")
	)
	(segment
		(start 218.69654 9.69264)
		(end 218.816174 9.521952)
		(width 0.14732)
		(layer "In11.Cu")
		(net "DELTA_L_85_10INCH_IN4_DN")
	)
	(segment
		(start 239.384586 2.95402)
		(end 239.74171 3.203702)
		(width 0.14732)
		(layer "In11.Cu")
		(net "DELTA_L_85_10INCH_IN4_DN")
	)
	(segment
		(start 234.525566 9.709912)
		(end 234.644946 9.539732)
		(width 0.14732)
		(layer "In11.Cu")
		(net "DELTA_L_85_10INCH_IN4_DN")
	)
	(segment
		(start 194.27444 3.194812)
		(end 195.85686 2.91592)
		(width 0.14732)
		(layer "In11.Cu")
		(net "DELTA_L_85_10INCH_IN4_DN")
	)
	(segment
		(start 200.187306 3.263646)
		(end 201.425302 10.284968)
		(width 0.14732)
		(layer "In11.Cu")
		(net "DELTA_L_85_10INCH_IN4_DN")
	)
	(segment
		(start 225.9457 3.307588)
		(end 227.528374 3.028696)
		(width 0.14732)
		(layer "In11.Cu")
		(net "DELTA_L_85_10INCH_IN4_DN")
	)
	(segment
		(start 225.696018 3.664458)
		(end 225.9457 3.307588)
		(width 0.14732)
		(layer "In11.Cu")
		(net "DELTA_L_85_10INCH_IN4_DN")
	)
	(segment
		(start 215.654636 3.004312)
		(end 216.011252 3.253994)
		(width 0.14732)
		(layer "In11.Cu")
		(net "DELTA_L_85_10INCH_IN4_DN")
	)
	(segment
		(start 229.034848 9.797796)
		(end 229.205028 9.917176)
		(width 0.14732)
		(layer "In11.Cu")
		(net "DELTA_L_85_10INCH_IN4_DN")
	)
	(segment
		(start 207.741266 3.000502)
		(end 208.097628 3.250438)
		(width 0.14732)
		(layer "In11.Cu")
		(net "DELTA_L_85_10INCH_IN4_DN")
	)
	(segment
		(start 239.74171 3.203702)
		(end 240.898172 9.76376)
		(width 0.14732)
		(layer "In11.Cu")
		(net "DELTA_L_85_10INCH_IN4_DN")
	)
	(segment
		(start 201.59599 10.404348)
		(end 202.954128 10.164826)
		(width 0.14732)
		(layer "In11.Cu")
		(net "DELTA_L_85_10INCH_IN4_DN")
	)
	(segment
		(start 242.546124 9.473438)
		(end 241.517678 3.639566)
		(width 0.14732)
		(layer "In11.Cu")
		(net "DELTA_L_85_10INCH_IN4_DN")
	)
	(segment
		(start 213.21395 9.827768)
		(end 213.384638 9.947402)
		(width 0.14732)
		(layer "In11.Cu")
		(net "DELTA_L_85_10INCH_IN4_DN")
	)
	(segment
		(start 226.724972 9.500108)
		(end 225.696018 3.664458)
		(width 0.14732)
		(layer "In11.Cu")
		(net "DELTA_L_85_10INCH_IN4_DN")
	)
	(segment
		(start 225.2472 9.90981)
		(end 226.605592 9.670288)
		(width 0.14732)
		(layer "In11.Cu")
		(net "DELTA_L_85_10INCH_IN4_DN")
	)
	(segment
		(start 227.528374 3.028696)
		(end 227.885244 3.27914)
		(width 0.14732)
		(layer "In11.Cu")
		(net "DELTA_L_85_10INCH_IN4_DN")
	)
	(segment
		(start 249.82932 2.671064)
		(end 249.148346 2.4892)
		(width 0.13208)
		(layer "F.Cu")
		(net "DELTA_L_85_10INCH_IN3_DP")
	)
	(segment
		(start 182.97144 2.671064)
		(end 183.652414 2.4892)
		(width 0.13208)
		(layer "F.Cu")
		(net "DELTA_L_85_10INCH_IN3_DP")
	)
	(segment
		(start 217.338402 7.392162)
		(end 218.69654 7.15264)
		(width 0.14732)
		(layer "In6.Cu")
		(net "DELTA_L_85_10INCH_IN3_DP")
	)
	(segment
		(start 194.024758 1.011428)
		(end 194.27444 0.654812)
		(width 0.14732)
		(layer "In6.Cu")
		(net "DELTA_L_85_10INCH_IN3_DP")
	)
	(segment
		(start 218.816174 6.981952)
		(end 217.784934 1.13284)
		(width 0.14732)
		(layer "In6.Cu")
		(net "DELTA_L_85_10INCH_IN3_DP")
	)
	(segment
		(start 195.85686 0.37592)
		(end 196.213476 0.625602)
		(width 0.14732)
		(layer "In6.Cu")
		(net "DELTA_L_85_10INCH_IN3_DP")
	)
	(segment
		(start 241.517678 1.099566)
		(end 241.76736 0.743458)
		(width 0.14732)
		(layer "In6.Cu")
		(net "DELTA_L_85_10INCH_IN3_DP")
	)
	(segment
		(start 225.2472 7.36981)
		(end 226.605592 7.130288)
		(width 0.14732)
		(layer "In6.Cu")
		(net "DELTA_L_85_10INCH_IN3_DP")
	)
	(segment
		(start 221.301564 7.43077)
		(end 222.659956 7.191502)
		(width 0.14732)
		(layer "In6.Cu")
		(net "DELTA_L_85_10INCH_IN3_DP")
	)
	(segment
		(start 223.918272 0.678688)
		(end 225.07702 7.25043)
		(width 0.14732)
		(layer "In6.Cu")
		(net "DELTA_L_85_10INCH_IN3_DP")
	)
	(segment
		(start 226.605592 7.130288)
		(end 226.724972 6.960108)
		(width 0.14732)
		(layer "In6.Cu")
		(net "DELTA_L_85_10INCH_IN3_DP")
	)
	(segment
		(start 209.490818 7.764018)
		(end 210.848956 7.524496)
		(width 0.14732)
		(layer "In6.Cu")
		(net "DELTA_L_85_10INCH_IN3_DP")
	)
	(segment
		(start 209.85734 1.05029)
		(end 210.107022 0.693674)
		(width 0.14732)
		(layer "In6.Cu")
		(net "DELTA_L_85_10INCH_IN3_DP")
	)
	(segment
		(start 193.688208 7.894574)
		(end 195.046346 7.655052)
		(width 0.14732)
		(layer "In6.Cu")
		(net "DELTA_L_85_10INCH_IN3_DP")
	)
	(segment
		(start 233.167174 7.409688)
		(end 234.525566 7.169912)
		(width 0.14732)
		(layer "In6.Cu")
		(net "DELTA_L_85_10INCH_IN3_DP")
	)
	(segment
		(start 193.51752 7.77494)
		(end 193.688208 7.894574)
		(width 0.14732)
		(layer "In6.Cu")
		(net "DELTA_L_85_10INCH_IN3_DP")
	)
	(segment
		(start 191.906652 0.412242)
		(end 192.263268 0.661924)
		(width 0.14732)
		(layer "In6.Cu")
		(net "DELTA_L_85_10INCH_IN3_DP")
	)
	(segment
		(start 234.525566 7.169912)
		(end 234.644946 6.999732)
		(width 0.14732)
		(layer "In6.Cu")
		(net "DELTA_L_85_10INCH_IN3_DP")
	)
	(segment
		(start 206.88808 7.498334)
		(end 207.007714 7.3279)
		(width 0.14732)
		(layer "In6.Cu")
		(net "DELTA_L_85_10INCH_IN3_DP")
	)
	(segment
		(start 238.590836 6.93928)
		(end 237.552484 1.049528)
		(width 0.14732)
		(layer "In6.Cu")
		(net "DELTA_L_85_10INCH_IN3_DP")
	)
	(segment
		(start 200.187306 0.723646)
		(end 201.425302 7.744968)
		(width 0.14732)
		(layer "In6.Cu")
		(net "DELTA_L_85_10INCH_IN3_DP")
	)
	(segment
		(start 213.384638 7.407402)
		(end 214.742776 7.16788)
		(width 0.14732)
		(layer "In6.Cu")
		(net "DELTA_L_85_10INCH_IN3_DP")
	)
	(segment
		(start 183.652414 2.4892)
		(end 183.947054 2.78384)
		(width 0.14732)
		(layer "In6.Cu")
		(net "DELTA_L_85_10INCH_IN3_DP")
	)
	(segment
		(start 239.384586 0.41402)
		(end 239.74171 0.663702)
		(width 0.14732)
		(layer "In6.Cu")
		(net "DELTA_L_85_10INCH_IN3_DP")
	)
	(segment
		(start 210.107022 0.693674)
		(end 211.689442 0.414782)
		(width 0.14732)
		(layer "In6.Cu")
		(net "DELTA_L_85_10INCH_IN3_DP")
	)
	(segment
		(start 217.784934 1.13284)
		(end 218.03487 0.77597)
		(width 0.14732)
		(layer "In6.Cu")
		(net "DELTA_L_85_10INCH_IN3_DP")
	)
	(segment
		(start 231.478328 0.450342)
		(end 231.834944 0.700532)
		(width 0.14732)
		(layer "In6.Cu")
		(net "DELTA_L_85_10INCH_IN3_DP")
	)
	(segment
		(start 233.60888 1.123188)
		(end 233.858562 0.766572)
		(width 0.14732)
		(layer "In6.Cu")
		(net "DELTA_L_85_10INCH_IN3_DP")
	)
	(segment
		(start 243.70665 0.713994)
		(end 244.047772 2.65049)
		(width 0.14732)
		(layer "In6.Cu")
		(net "DELTA_L_85_10INCH_IN3_DP")
	)
	(segment
		(start 221.13113 7.31139)
		(end 221.301564 7.43077)
		(width 0.14732)
		(layer "In6.Cu")
		(net "DELTA_L_85_10INCH_IN3_DP")
	)
	(segment
		(start 218.69654 7.15264)
		(end 218.816174 6.981952)
		(width 0.14732)
		(layer "In6.Cu")
		(net "DELTA_L_85_10INCH_IN3_DP")
	)
	(segment
		(start 239.74171 0.663702)
		(end 240.898172 7.22376)
		(width 0.14732)
		(layer "In6.Cu")
		(net "DELTA_L_85_10INCH_IN3_DP")
	)
	(segment
		(start 202.195684 0.702056)
		(end 203.778104 0.42291)
		(width 0.14732)
		(layer "In6.Cu")
		(net "DELTA_L_85_10INCH_IN3_DP")
	)
	(segment
		(start 248.853706 2.78384)
		(end 249.148346 2.4892)
		(width 0.14732)
		(layer "In6.Cu")
		(net "DELTA_L_85_10INCH_IN3_DP")
	)
	(segment
		(start 225.696018 1.124458)
		(end 225.9457 0.767588)
		(width 0.14732)
		(layer "In6.Cu")
		(net "DELTA_L_85_10INCH_IN3_DP")
	)
	(segment
		(start 216.011252 0.713994)
		(end 217.167968 7.272782)
		(width 0.14732)
		(layer "In6.Cu")
		(net "DELTA_L_85_10INCH_IN3_DP")
	)
	(segment
		(start 235.798106 0.737108)
		(end 236.942884 7.229856)
		(width 0.14732)
		(layer "In6.Cu")
		(net "DELTA_L_85_10INCH_IN3_DP")
	)
	(segment
		(start 205.529942 7.737602)
		(end 206.88808 7.498334)
		(width 0.14732)
		(layer "In6.Cu")
		(net "DELTA_L_85_10INCH_IN3_DP")
	)
	(segment
		(start 222.779336 7.020814)
		(end 221.729046 1.064768)
		(width 0.14732)
		(layer "In6.Cu")
		(net "DELTA_L_85_10INCH_IN3_DP")
	)
	(segment
		(start 232.99674 7.290308)
		(end 233.167174 7.409688)
		(width 0.14732)
		(layer "In6.Cu")
		(net "DELTA_L_85_10INCH_IN3_DP")
	)
	(segment
		(start 189.729872 7.884668)
		(end 191.08801 7.645146)
		(width 0.14732)
		(layer "In6.Cu")
		(net "DELTA_L_85_10INCH_IN3_DP")
	)
	(segment
		(start 244.206522 2.78384)
		(end 248.853706 2.78384)
		(width 0.14732)
		(layer "In6.Cu")
		(net "DELTA_L_85_10INCH_IN3_DP")
	)
	(segment
		(start 241.068606 7.34314)
		(end 242.426998 7.104126)
		(width 0.14732)
		(layer "In6.Cu")
		(net "DELTA_L_85_10INCH_IN3_DP")
	)
	(segment
		(start 210.96859 7.353554)
		(end 209.85734 1.05029)
		(width 0.14732)
		(layer "In6.Cu")
		(net "DELTA_L_85_10INCH_IN3_DP")
	)
	(segment
		(start 215.654636 0.464312)
		(end 216.011252 0.713994)
		(width 0.14732)
		(layer "In6.Cu")
		(net "DELTA_L_85_10INCH_IN3_DP")
	)
	(segment
		(start 204.13472 0.672592)
		(end 205.359 7.618222)
		(width 0.14732)
		(layer "In6.Cu")
		(net "DELTA_L_85_10INCH_IN3_DP")
	)
	(segment
		(start 229.645972 1.086612)
		(end 229.895654 0.729488)
		(width 0.14732)
		(layer "In6.Cu")
		(net "DELTA_L_85_10INCH_IN3_DP")
	)
	(segment
		(start 201.59599 7.864348)
		(end 202.954128 7.624826)
		(width 0.14732)
		(layer "In6.Cu")
		(net "DELTA_L_85_10INCH_IN3_DP")
	)
	(segment
		(start 219.617036 0.496824)
		(end 219.973398 0.746506)
		(width 0.14732)
		(layer "In6.Cu")
		(net "DELTA_L_85_10INCH_IN3_DP")
	)
	(segment
		(start 229.205028 7.377176)
		(end 230.56342 7.137654)
		(width 0.14732)
		(layer "In6.Cu")
		(net "DELTA_L_85_10INCH_IN3_DP")
	)
	(segment
		(start 231.834944 0.700532)
		(end 232.99674 7.290308)
		(width 0.14732)
		(layer "In6.Cu")
		(net "DELTA_L_85_10INCH_IN3_DP")
	)
	(segment
		(start 242.546124 6.933438)
		(end 241.517678 1.099566)
		(width 0.14732)
		(layer "In6.Cu")
		(net "DELTA_L_85_10INCH_IN3_DP")
	)
	(segment
		(start 195.046346 7.655052)
		(end 195.16598 7.484618)
		(width 0.14732)
		(layer "In6.Cu")
		(net "DELTA_L_85_10INCH_IN3_DP")
	)
	(segment
		(start 230.56342 7.137654)
		(end 230.6828 6.967474)
		(width 0.14732)
		(layer "In6.Cu")
		(net "DELTA_L_85_10INCH_IN3_DP")
	)
	(segment
		(start 203.073762 7.454138)
		(end 201.946002 1.058672)
		(width 0.14732)
		(layer "In6.Cu")
		(net "DELTA_L_85_10INCH_IN3_DP")
	)
	(segment
		(start 198.99503 7.61238)
		(end 199.114664 7.441692)
		(width 0.14732)
		(layer "In6.Cu")
		(net "DELTA_L_85_10INCH_IN3_DP")
	)
	(segment
		(start 227.885244 0.73914)
		(end 229.034848 7.257796)
		(width 0.14732)
		(layer "In6.Cu")
		(net "DELTA_L_85_10INCH_IN3_DP")
	)
	(segment
		(start 213.822534 1.100074)
		(end 214.072216 0.743204)
		(width 0.14732)
		(layer "In6.Cu")
		(net "DELTA_L_85_10INCH_IN3_DP")
	)
	(segment
		(start 196.213476 0.625602)
		(end 197.466204 7.732522)
		(width 0.14732)
		(layer "In6.Cu")
		(net "DELTA_L_85_10INCH_IN3_DP")
	)
	(segment
		(start 191.08801 7.645146)
		(end 191.207644 7.474712)
		(width 0.14732)
		(layer "In6.Cu")
		(net "DELTA_L_85_10INCH_IN3_DP")
	)
	(segment
		(start 229.034848 7.257796)
		(end 229.205028 7.377176)
		(width 0.14732)
		(layer "In6.Cu")
		(net "DELTA_L_85_10INCH_IN3_DP")
	)
	(segment
		(start 218.03487 0.77597)
		(end 219.617036 0.496824)
		(width 0.14732)
		(layer "In6.Cu")
		(net "DELTA_L_85_10INCH_IN3_DP")
	)
	(segment
		(start 223.561148 0.429006)
		(end 223.918272 0.678688)
		(width 0.14732)
		(layer "In6.Cu")
		(net "DELTA_L_85_10INCH_IN3_DP")
	)
	(segment
		(start 213.21395 7.287768)
		(end 213.384638 7.407402)
		(width 0.14732)
		(layer "In6.Cu")
		(net "DELTA_L_85_10INCH_IN3_DP")
	)
	(segment
		(start 191.207644 7.474712)
		(end 190.07455 1.04775)
		(width 0.14732)
		(layer "In6.Cu")
		(net "DELTA_L_85_10INCH_IN3_DP")
	)
	(segment
		(start 188.415422 2.78384)
		(end 188.727334 3.04546)
		(width 0.14732)
		(layer "In6.Cu")
		(net "DELTA_L_85_10INCH_IN3_DP")
	)
	(segment
		(start 225.07702 7.25043)
		(end 225.2472 7.36981)
		(width 0.14732)
		(layer "In6.Cu")
		(net "DELTA_L_85_10INCH_IN3_DP")
	)
	(segment
		(start 208.097628 0.710438)
		(end 209.320384 7.644384)
		(width 0.14732)
		(layer "In6.Cu")
		(net "DELTA_L_85_10INCH_IN3_DP")
	)
	(segment
		(start 207.741266 0.460502)
		(end 208.097628 0.710438)
		(width 0.14732)
		(layer "In6.Cu")
		(net "DELTA_L_85_10INCH_IN3_DP")
	)
	(segment
		(start 235.440982 0.487426)
		(end 235.798106 0.737108)
		(width 0.14732)
		(layer "In6.Cu")
		(net "DELTA_L_85_10INCH_IN3_DP")
	)
	(segment
		(start 229.895654 0.729488)
		(end 231.478328 0.450342)
		(width 0.14732)
		(layer "In6.Cu")
		(net "DELTA_L_85_10INCH_IN3_DP")
	)
	(segment
		(start 211.689442 0.414782)
		(end 212.046058 0.664464)
		(width 0.14732)
		(layer "In6.Cu")
		(net "DELTA_L_85_10INCH_IN3_DP")
	)
	(segment
		(start 233.858562 0.766572)
		(end 235.440982 0.487426)
		(width 0.14732)
		(layer "In6.Cu")
		(net "DELTA_L_85_10INCH_IN3_DP")
	)
	(segment
		(start 214.072216 0.743204)
		(end 215.654636 0.464312)
		(width 0.14732)
		(layer "In6.Cu")
		(net "DELTA_L_85_10INCH_IN3_DP")
	)
	(segment
		(start 203.778104 0.42291)
		(end 204.13472 0.672592)
		(width 0.14732)
		(layer "In6.Cu")
		(net "DELTA_L_85_10INCH_IN3_DP")
	)
	(segment
		(start 207.007714 7.3279)
		(end 205.909164 1.096264)
		(width 0.14732)
		(layer "In6.Cu")
		(net "DELTA_L_85_10INCH_IN3_DP")
	)
	(segment
		(start 201.425302 7.744968)
		(end 201.59599 7.864348)
		(width 0.14732)
		(layer "In6.Cu")
		(net "DELTA_L_85_10INCH_IN3_DP")
	)
	(segment
		(start 202.954128 7.624826)
		(end 203.073762 7.454138)
		(width 0.14732)
		(layer "In6.Cu")
		(net "DELTA_L_85_10INCH_IN3_DP")
	)
	(segment
		(start 197.466204 7.732522)
		(end 197.636892 7.851902)
		(width 0.14732)
		(layer "In6.Cu")
		(net "DELTA_L_85_10INCH_IN3_DP")
	)
	(segment
		(start 192.263268 0.661924)
		(end 193.51752 7.77494)
		(width 0.14732)
		(layer "In6.Cu")
		(net "DELTA_L_85_10INCH_IN3_DP")
	)
	(segment
		(start 244.047772 2.65049)
		(end 244.206522 2.78384)
		(width 0.14732)
		(layer "In6.Cu")
		(net "DELTA_L_85_10INCH_IN3_DP")
	)
	(segment
		(start 243.349526 0.464312)
		(end 243.70665 0.713994)
		(width 0.14732)
		(layer "In6.Cu")
		(net "DELTA_L_85_10INCH_IN3_DP")
	)
	(segment
		(start 183.947054 2.78384)
		(end 188.415422 2.78384)
		(width 0.14732)
		(layer "In6.Cu")
		(net "DELTA_L_85_10INCH_IN3_DP")
	)
	(segment
		(start 209.320384 7.644384)
		(end 209.490818 7.764018)
		(width 0.14732)
		(layer "In6.Cu")
		(net "DELTA_L_85_10INCH_IN3_DP")
	)
	(segment
		(start 194.27444 0.654812)
		(end 195.85686 0.37592)
		(width 0.14732)
		(layer "In6.Cu")
		(net "DELTA_L_85_10INCH_IN3_DP")
	)
	(segment
		(start 189.559184 7.765034)
		(end 189.729872 7.884668)
		(width 0.14732)
		(layer "In6.Cu")
		(net "DELTA_L_85_10INCH_IN3_DP")
	)
	(segment
		(start 241.76736 0.743458)
		(end 243.349526 0.464312)
		(width 0.14732)
		(layer "In6.Cu")
		(net "DELTA_L_85_10INCH_IN3_DP")
	)
	(segment
		(start 214.86241 6.997192)
		(end 213.822534 1.100074)
		(width 0.14732)
		(layer "In6.Cu")
		(net "DELTA_L_85_10INCH_IN3_DP")
	)
	(segment
		(start 201.946002 1.058672)
		(end 202.195684 0.702056)
		(width 0.14732)
		(layer "In6.Cu")
		(net "DELTA_L_85_10INCH_IN3_DP")
	)
	(segment
		(start 237.802166 0.693166)
		(end 239.384586 0.41402)
		(width 0.14732)
		(layer "In6.Cu")
		(net "DELTA_L_85_10INCH_IN3_DP")
	)
	(segment
		(start 225.9457 0.767588)
		(end 227.528374 0.488696)
		(width 0.14732)
		(layer "In6.Cu")
		(net "DELTA_L_85_10INCH_IN3_DP")
	)
	(segment
		(start 221.978982 0.708152)
		(end 223.561148 0.429006)
		(width 0.14732)
		(layer "In6.Cu")
		(net "DELTA_L_85_10INCH_IN3_DP")
	)
	(segment
		(start 198.24827 0.75311)
		(end 199.83069 0.473964)
		(width 0.14732)
		(layer "In6.Cu")
		(net "DELTA_L_85_10INCH_IN3_DP")
	)
	(segment
		(start 197.636892 7.851902)
		(end 198.99503 7.61238)
		(width 0.14732)
		(layer "In6.Cu")
		(net "DELTA_L_85_10INCH_IN3_DP")
	)
	(segment
		(start 190.07455 1.04775)
		(end 190.324232 0.691134)
		(width 0.14732)
		(layer "In6.Cu")
		(net "DELTA_L_85_10INCH_IN3_DP")
	)
	(segment
		(start 227.528374 0.488696)
		(end 227.885244 0.73914)
		(width 0.14732)
		(layer "In6.Cu")
		(net "DELTA_L_85_10INCH_IN3_DP")
	)
	(segment
		(start 242.426998 7.104126)
		(end 242.546124 6.933438)
		(width 0.14732)
		(layer "In6.Cu")
		(net "DELTA_L_85_10INCH_IN3_DP")
	)
	(segment
		(start 188.727334 3.04546)
		(end 189.559184 7.765034)
		(width 0.14732)
		(layer "In6.Cu")
		(net "DELTA_L_85_10INCH_IN3_DP")
	)
	(segment
		(start 230.6828 6.967474)
		(end 229.645972 1.086612)
		(width 0.14732)
		(layer "In6.Cu")
		(net "DELTA_L_85_10INCH_IN3_DP")
	)
	(segment
		(start 199.83069 0.473964)
		(end 200.187306 0.723646)
		(width 0.14732)
		(layer "In6.Cu")
		(net "DELTA_L_85_10INCH_IN3_DP")
	)
	(segment
		(start 221.729046 1.064768)
		(end 221.978982 0.708152)
		(width 0.14732)
		(layer "In6.Cu")
		(net "DELTA_L_85_10INCH_IN3_DP")
	)
	(segment
		(start 236.942884 7.229856)
		(end 237.113064 7.349236)
		(width 0.14732)
		(layer "In6.Cu")
		(net "DELTA_L_85_10INCH_IN3_DP")
	)
	(segment
		(start 237.113064 7.349236)
		(end 238.471456 7.109968)
		(width 0.14732)
		(layer "In6.Cu")
		(net "DELTA_L_85_10INCH_IN3_DP")
	)
	(segment
		(start 234.644946 6.999732)
		(end 233.60888 1.123188)
		(width 0.14732)
		(layer "In6.Cu")
		(net "DELTA_L_85_10INCH_IN3_DP")
	)
	(segment
		(start 199.114664 7.441692)
		(end 197.998588 1.10998)
		(width 0.14732)
		(layer "In6.Cu")
		(net "DELTA_L_85_10INCH_IN3_DP")
	)
	(segment
		(start 237.552484 1.049528)
		(end 237.802166 0.693166)
		(width 0.14732)
		(layer "In6.Cu")
		(net "DELTA_L_85_10INCH_IN3_DP")
	)
	(segment
		(start 219.973398 0.746506)
		(end 221.13113 7.31139)
		(width 0.14732)
		(layer "In6.Cu")
		(net "DELTA_L_85_10INCH_IN3_DP")
	)
	(segment
		(start 238.471456 7.109968)
		(end 238.590836 6.93928)
		(width 0.14732)
		(layer "In6.Cu")
		(net "DELTA_L_85_10INCH_IN3_DP")
	)
	(segment
		(start 226.724972 6.960108)
		(end 225.696018 1.124458)
		(width 0.14732)
		(layer "In6.Cu")
		(net "DELTA_L_85_10INCH_IN3_DP")
	)
	(segment
		(start 197.998588 1.10998)
		(end 198.24827 0.75311)
		(width 0.14732)
		(layer "In6.Cu")
		(net "DELTA_L_85_10INCH_IN3_DP")
	)
	(segment
		(start 210.848956 7.524496)
		(end 210.96859 7.353554)
		(width 0.14732)
		(layer "In6.Cu")
		(net "DELTA_L_85_10INCH_IN3_DP")
	)
	(segment
		(start 205.359 7.618222)
		(end 205.529942 7.737602)
		(width 0.14732)
		(layer "In6.Cu")
		(net "DELTA_L_85_10INCH_IN3_DP")
	)
	(segment
		(start 206.158846 0.739648)
		(end 207.741266 0.460502)
		(width 0.14732)
		(layer "In6.Cu")
		(net "DELTA_L_85_10INCH_IN3_DP")
	)
	(segment
		(start 195.16598 7.484618)
		(end 194.024758 1.011428)
		(width 0.14732)
		(layer "In6.Cu")
		(net "DELTA_L_85_10INCH_IN3_DP")
	)
	(segment
		(start 190.324232 0.691134)
		(end 191.906652 0.412242)
		(width 0.14732)
		(layer "In6.Cu")
		(net "DELTA_L_85_10INCH_IN3_DP")
	)
	(segment
		(start 217.167968 7.272782)
		(end 217.338402 7.392162)
		(width 0.14732)
		(layer "In6.Cu")
		(net "DELTA_L_85_10INCH_IN3_DP")
	)
	(segment
		(start 212.046058 0.664464)
		(end 213.21395 7.287768)
		(width 0.14732)
		(layer "In6.Cu")
		(net "DELTA_L_85_10INCH_IN3_DP")
	)
	(segment
		(start 222.659956 7.191502)
		(end 222.779336 7.020814)
		(width 0.14732)
		(layer "In6.Cu")
		(net "DELTA_L_85_10INCH_IN3_DP")
	)
	(segment
		(start 214.742776 7.16788)
		(end 214.86241 6.997192)
		(width 0.14732)
		(layer "In6.Cu")
		(net "DELTA_L_85_10INCH_IN3_DP")
	)
	(segment
		(start 240.898172 7.22376)
		(end 241.068606 7.34314)
		(width 0.14732)
		(layer "In6.Cu")
		(net "DELTA_L_85_10INCH_IN3_DP")
	)
	(segment
		(start 205.909164 1.096264)
		(end 206.158846 0.739648)
		(width 0.14732)
		(layer "In6.Cu")
		(net "DELTA_L_85_10INCH_IN3_DP")
	)
	(segment
		(start 182.97144 3.170936)
		(end 183.652414 3.3528)
		(width 0.13208)
		(layer "F.Cu")
		(net "DELTA_L_85_10INCH_IN3_DN")
	)
	(segment
		(start 249.82932 3.170936)
		(end 249.148346 3.3528)
		(width 0.13208)
		(layer "F.Cu")
		(net "DELTA_L_85_10INCH_IN3_DN")
	)
	(segment
		(start 243.794788 2.79654)
		(end 244.106446 3.05816)
		(width 0.14732)
		(layer "In6.Cu")
		(net "DELTA_L_85_10INCH_IN3_DN")
	)
	(segment
		(start 220.880686 7.470902)
		(end 221.237302 7.720838)
		(width 0.14732)
		(layer "In6.Cu")
		(net "DELTA_L_85_10INCH_IN3_DN")
	)
	(segment
		(start 223.496886 0.719074)
		(end 223.667828 0.838454)
		(width 0.14732)
		(layer "In6.Cu")
		(net "DELTA_L_85_10INCH_IN3_DN")
	)
	(segment
		(start 222.138494 0.958596)
		(end 222.138494 0.95885)
		(width 0.14732)
		(layer "In6.Cu")
		(net "DELTA_L_85_10INCH_IN3_DN")
	)
	(segment
		(start 198.288656 1.174242)
		(end 198.408036 1.003808)
		(width 0.14732)
		(layer "In6.Cu")
		(net "DELTA_L_85_10INCH_IN3_DN")
	)
	(segment
		(start 239.491012 0.823468)
		(end 240.647728 7.383272)
		(width 0.14732)
		(layer "In6.Cu")
		(net "DELTA_L_85_10INCH_IN3_DN")
	)
	(segment
		(start 236.69244 7.389368)
		(end 237.048548 7.639304)
		(width 0.14732)
		(layer "In6.Cu")
		(net "DELTA_L_85_10INCH_IN3_DN")
	)
	(segment
		(start 217.27414 7.68223)
		(end 218.856052 7.403084)
		(width 0.14732)
		(layer "In6.Cu")
		(net "DELTA_L_85_10INCH_IN3_DN")
	)
	(segment
		(start 221.237302 7.720838)
		(end 222.819722 7.4422)
		(width 0.14732)
		(layer "In6.Cu")
		(net "DELTA_L_85_10INCH_IN3_DN")
	)
	(segment
		(start 211.008722 7.775194)
		(end 211.258658 7.417816)
		(width 0.14732)
		(layer "In6.Cu")
		(net "DELTA_L_85_10INCH_IN3_DN")
	)
	(segment
		(start 235.37672 0.777494)
		(end 235.547662 0.896874)
		(width 0.14732)
		(layer "In6.Cu")
		(net "DELTA_L_85_10INCH_IN3_DN")
	)
	(segment
		(start 198.408036 1.003808)
		(end 199.766428 0.764032)
		(width 0.14732)
		(layer "In6.Cu")
		(net "DELTA_L_85_10INCH_IN3_DN")
	)
	(segment
		(start 219.106242 7.046468)
		(end 218.075002 1.197356)
		(width 0.14732)
		(layer "In6.Cu")
		(net "DELTA_L_85_10INCH_IN3_DN")
	)
	(segment
		(start 230.05542 0.979932)
		(end 230.05542 0.980186)
		(width 0.14732)
		(layer "In6.Cu")
		(net "DELTA_L_85_10INCH_IN3_DN")
	)
	(segment
		(start 234.685078 7.420356)
		(end 234.935014 7.064248)
		(width 0.14732)
		(layer "In6.Cu")
		(net "DELTA_L_85_10INCH_IN3_DN")
	)
	(segment
		(start 191.84239 0.70231)
		(end 192.01257 0.82169)
		(width 0.14732)
		(layer "In6.Cu")
		(net "DELTA_L_85_10INCH_IN3_DN")
	)
	(segment
		(start 199.404732 7.506208)
		(end 198.288656 1.174242)
		(width 0.14732)
		(layer "In6.Cu")
		(net "DELTA_L_85_10INCH_IN3_DN")
	)
	(segment
		(start 242.586764 7.35457)
		(end 242.836192 6.9977)
		(width 0.14732)
		(layer "In6.Cu")
		(net "DELTA_L_85_10INCH_IN3_DN")
	)
	(segment
		(start 210.147408 1.114806)
		(end 210.266788 0.944372)
		(width 0.14732)
		(layer "In6.Cu")
		(net "DELTA_L_85_10INCH_IN3_DN")
	)
	(segment
		(start 189.30874 7.924546)
		(end 189.665356 8.174736)
		(width 0.14732)
		(layer "In6.Cu")
		(net "DELTA_L_85_10INCH_IN3_DN")
	)
	(segment
		(start 203.884022 0.832358)
		(end 205.108556 7.777988)
		(width 0.14732)
		(layer "In6.Cu")
		(net "DELTA_L_85_10INCH_IN3_DN")
	)
	(segment
		(start 242.836192 6.9977)
		(end 241.807746 1.164082)
		(width 0.14732)
		(layer "In6.Cu")
		(net "DELTA_L_85_10INCH_IN3_DN")
	)
	(segment
		(start 205.46568 8.02767)
		(end 207.047592 7.749032)
		(width 0.14732)
		(layer "In6.Cu")
		(net "DELTA_L_85_10INCH_IN3_DN")
	)
	(segment
		(start 218.194382 1.026668)
		(end 219.552774 0.786892)
		(width 0.14732)
		(layer "In6.Cu")
		(net "DELTA_L_85_10INCH_IN3_DN")
	)
	(segment
		(start 194.434206 0.90551)
		(end 195.792598 0.665988)
		(width 0.14732)
		(layer "In6.Cu")
		(net "DELTA_L_85_10INCH_IN3_DN")
	)
	(segment
		(start 222.138494 0.95885)
		(end 223.496886 0.719074)
		(width 0.14732)
		(layer "In6.Cu")
		(net "DELTA_L_85_10INCH_IN3_DN")
	)
	(segment
		(start 195.456048 7.549134)
		(end 194.314826 1.075944)
		(width 0.14732)
		(layer "In6.Cu")
		(net "DELTA_L_85_10INCH_IN3_DN")
	)
	(segment
		(start 197.215506 7.892288)
		(end 197.57263 8.14197)
		(width 0.14732)
		(layer "In6.Cu")
		(net "DELTA_L_85_10INCH_IN3_DN")
	)
	(segment
		(start 202.23607 1.122934)
		(end 202.35545 0.952754)
		(width 0.14732)
		(layer "In6.Cu")
		(net "DELTA_L_85_10INCH_IN3_DN")
	)
	(segment
		(start 238.631222 7.360666)
		(end 238.880904 7.003542)
		(width 0.14732)
		(layer "In6.Cu")
		(net "DELTA_L_85_10INCH_IN3_DN")
	)
	(segment
		(start 239.320324 0.704088)
		(end 239.491012 0.823468)
		(width 0.14732)
		(layer "In6.Cu")
		(net "DELTA_L_85_10INCH_IN3_DN")
	)
	(segment
		(start 233.102912 7.699756)
		(end 234.685078 7.420356)
		(width 0.14732)
		(layer "In6.Cu")
		(net "DELTA_L_85_10INCH_IN3_DN")
	)
	(segment
		(start 183.652414 3.3528)
		(end 183.947054 3.05816)
		(width 0.14732)
		(layer "In6.Cu")
		(net "DELTA_L_85_10INCH_IN3_DN")
	)
	(segment
		(start 237.048548 7.639304)
		(end 238.631222 7.360666)
		(width 0.14732)
		(layer "In6.Cu")
		(net "DELTA_L_85_10INCH_IN3_DN")
	)
	(segment
		(start 211.62518 0.70485)
		(end 211.79536 0.82423)
		(width 0.14732)
		(layer "In6.Cu")
		(net "DELTA_L_85_10INCH_IN3_DN")
	)
	(segment
		(start 231.5845 0.860044)
		(end 232.746296 7.44982)
		(width 0.14732)
		(layer "In6.Cu")
		(net "DELTA_L_85_10INCH_IN3_DN")
	)
	(segment
		(start 183.947054 3.05816)
		(end 188.3156 3.05816)
		(width 0.14732)
		(layer "In6.Cu")
		(net "DELTA_L_85_10INCH_IN3_DN")
	)
	(segment
		(start 241.00409 7.633208)
		(end 242.586764 7.35457)
		(width 0.14732)
		(layer "In6.Cu")
		(net "DELTA_L_85_10INCH_IN3_DN")
	)
	(segment
		(start 244.106446 3.05816)
		(end 248.853706 3.05816)
		(width 0.14732)
		(layer "In6.Cu")
		(net "DELTA_L_85_10INCH_IN3_DN")
	)
	(segment
		(start 201.174604 7.904734)
		(end 201.531728 8.154416)
		(width 0.14732)
		(layer "In6.Cu")
		(net "DELTA_L_85_10INCH_IN3_DN")
	)
	(segment
		(start 215.760554 0.87376)
		(end 216.917524 7.432294)
		(width 0.14732)
		(layer "In6.Cu")
		(net "DELTA_L_85_10INCH_IN3_DN")
	)
	(segment
		(start 203.11364 7.87527)
		(end 203.36383 7.518654)
		(width 0.14732)
		(layer "In6.Cu")
		(net "DELTA_L_85_10INCH_IN3_DN")
	)
	(segment
		(start 201.531728 8.154416)
		(end 203.11364 7.87527)
		(width 0.14732)
		(layer "In6.Cu")
		(net "DELTA_L_85_10INCH_IN3_DN")
	)
	(segment
		(start 218.075002 1.197356)
		(end 218.194382 1.026414)
		(width 0.14732)
		(layer "In6.Cu")
		(net "DELTA_L_85_10INCH_IN3_DN")
	)
	(segment
		(start 189.665356 8.174736)
		(end 191.247522 7.895844)
		(width 0.14732)
		(layer "In6.Cu")
		(net "DELTA_L_85_10INCH_IN3_DN")
	)
	(segment
		(start 207.67675 0.75057)
		(end 207.847184 0.86995)
		(width 0.14732)
		(layer "In6.Cu")
		(net "DELTA_L_85_10INCH_IN3_DN")
	)
	(segment
		(start 199.766428 0.764032)
		(end 199.936608 0.883412)
		(width 0.14732)
		(layer "In6.Cu")
		(net "DELTA_L_85_10INCH_IN3_DN")
	)
	(segment
		(start 191.497712 7.539228)
		(end 190.364618 1.112266)
		(width 0.14732)
		(layer "In6.Cu")
		(net "DELTA_L_85_10INCH_IN3_DN")
	)
	(segment
		(start 222.019114 1.129284)
		(end 222.138494 0.958596)
		(width 0.14732)
		(layer "In6.Cu")
		(net "DELTA_L_85_10INCH_IN3_DN")
	)
	(segment
		(start 243.455952 0.87376)
		(end 243.794788 2.79654)
		(width 0.14732)
		(layer "In6.Cu")
		(net "DELTA_L_85_10INCH_IN3_DN")
	)
	(segment
		(start 203.713842 0.712978)
		(end 203.884022 0.832358)
		(width 0.14732)
		(layer "In6.Cu")
		(net "DELTA_L_85_10INCH_IN3_DN")
	)
	(segment
		(start 194.314826 1.075944)
		(end 194.434206 0.90551)
		(width 0.14732)
		(layer "In6.Cu")
		(net "DELTA_L_85_10INCH_IN3_DN")
	)
	(segment
		(start 188.47435 3.19151)
		(end 189.30874 7.924546)
		(width 0.14732)
		(layer "In6.Cu")
		(net "DELTA_L_85_10INCH_IN3_DN")
	)
	(segment
		(start 190.483998 0.941832)
		(end 191.84239 0.70231)
		(width 0.14732)
		(layer "In6.Cu")
		(net "DELTA_L_85_10INCH_IN3_DN")
	)
	(segment
		(start 227.463858 0.778764)
		(end 227.634546 0.898652)
		(width 0.14732)
		(layer "In6.Cu")
		(net "DELTA_L_85_10INCH_IN3_DN")
	)
	(segment
		(start 193.623692 8.184642)
		(end 195.205858 7.90575)
		(width 0.14732)
		(layer "In6.Cu")
		(net "DELTA_L_85_10INCH_IN3_DN")
	)
	(segment
		(start 238.880904 7.003542)
		(end 237.842552 1.114298)
		(width 0.14732)
		(layer "In6.Cu")
		(net "DELTA_L_85_10INCH_IN3_DN")
	)
	(segment
		(start 211.79536 0.82423)
		(end 212.963506 7.44728)
		(width 0.14732)
		(layer "In6.Cu")
		(net "DELTA_L_85_10INCH_IN3_DN")
	)
	(segment
		(start 229.93604 1.150874)
		(end 230.05542 0.979932)
		(width 0.14732)
		(layer "In6.Cu")
		(net "DELTA_L_85_10INCH_IN3_DN")
	)
	(segment
		(start 226.105466 1.018286)
		(end 227.463858 0.778764)
		(width 0.14732)
		(layer "In6.Cu")
		(net "DELTA_L_85_10INCH_IN3_DN")
	)
	(segment
		(start 230.05542 0.980186)
		(end 231.413812 0.74041)
		(width 0.14732)
		(layer "In6.Cu")
		(net "DELTA_L_85_10INCH_IN3_DN")
	)
	(segment
		(start 225.182684 7.659878)
		(end 226.765104 7.380732)
		(width 0.14732)
		(layer "In6.Cu")
		(net "DELTA_L_85_10INCH_IN3_DN")
	)
	(segment
		(start 248.853706 3.05816)
		(end 249.148346 3.3528)
		(width 0.14732)
		(layer "In6.Cu")
		(net "DELTA_L_85_10INCH_IN3_DN")
	)
	(segment
		(start 228.784404 7.417308)
		(end 229.140512 7.667244)
		(width 0.14732)
		(layer "In6.Cu")
		(net "DELTA_L_85_10INCH_IN3_DN")
	)
	(segment
		(start 205.108556 7.777988)
		(end 205.46568 8.02767)
		(width 0.14732)
		(layer "In6.Cu")
		(net "DELTA_L_85_10INCH_IN3_DN")
	)
	(segment
		(start 243.285264 0.75438)
		(end 243.455952 0.87376)
		(width 0.14732)
		(layer "In6.Cu")
		(net "DELTA_L_85_10INCH_IN3_DN")
	)
	(segment
		(start 207.047592 7.749032)
		(end 207.297782 7.392416)
		(width 0.14732)
		(layer "In6.Cu")
		(net "DELTA_L_85_10INCH_IN3_DN")
	)
	(segment
		(start 237.842552 1.114298)
		(end 237.961678 0.94361)
		(width 0.14732)
		(layer "In6.Cu")
		(net "DELTA_L_85_10INCH_IN3_DN")
	)
	(segment
		(start 209.069686 7.803896)
		(end 209.426302 8.054086)
		(width 0.14732)
		(layer "In6.Cu")
		(net "DELTA_L_85_10INCH_IN3_DN")
	)
	(segment
		(start 214.902288 7.418324)
		(end 215.152478 7.061708)
		(width 0.14732)
		(layer "In6.Cu")
		(net "DELTA_L_85_10INCH_IN3_DN")
	)
	(segment
		(start 215.152478 7.061708)
		(end 214.112602 1.164336)
		(width 0.14732)
		(layer "In6.Cu")
		(net "DELTA_L_85_10INCH_IN3_DN")
	)
	(segment
		(start 191.247522 7.895844)
		(end 191.497712 7.539228)
		(width 0.14732)
		(layer "In6.Cu")
		(net "DELTA_L_85_10INCH_IN3_DN")
	)
	(segment
		(start 227.634546 0.898652)
		(end 228.784404 7.417308)
		(width 0.14732)
		(layer "In6.Cu")
		(net "DELTA_L_85_10INCH_IN3_DN")
	)
	(segment
		(start 213.320122 7.69747)
		(end 214.902288 7.418324)
		(width 0.14732)
		(layer "In6.Cu")
		(net "DELTA_L_85_10INCH_IN3_DN")
	)
	(segment
		(start 234.018328 1.01727)
		(end 235.37672 0.777494)
		(width 0.14732)
		(layer "In6.Cu")
		(net "DELTA_L_85_10INCH_IN3_DN")
	)
	(segment
		(start 222.819722 7.4422)
		(end 223.069404 7.085076)
		(width 0.14732)
		(layer "In6.Cu")
		(net "DELTA_L_85_10INCH_IN3_DN")
	)
	(segment
		(start 241.807746 1.164082)
		(end 241.926872 0.993902)
		(width 0.14732)
		(layer "In6.Cu")
		(net "DELTA_L_85_10INCH_IN3_DN")
	)
	(segment
		(start 225.986086 1.18872)
		(end 226.105466 1.018286)
		(width 0.14732)
		(layer "In6.Cu")
		(net "DELTA_L_85_10INCH_IN3_DN")
	)
	(segment
		(start 231.413812 0.74041)
		(end 231.5845 0.860044)
		(width 0.14732)
		(layer "In6.Cu")
		(net "DELTA_L_85_10INCH_IN3_DN")
	)
	(segment
		(start 232.746296 7.44982)
		(end 233.102912 7.699756)
		(width 0.14732)
		(layer "In6.Cu")
		(net "DELTA_L_85_10INCH_IN3_DN")
	)
	(segment
		(start 188.3156 3.05816)
		(end 188.47435 3.19151)
		(width 0.14732)
		(layer "In6.Cu")
		(net "DELTA_L_85_10INCH_IN3_DN")
	)
	(segment
		(start 202.35545 0.952754)
		(end 203.713842 0.712978)
		(width 0.14732)
		(layer "In6.Cu")
		(net "DELTA_L_85_10INCH_IN3_DN")
	)
	(segment
		(start 218.194382 1.026414)
		(end 218.194382 1.026668)
		(width 0.14732)
		(layer "In6.Cu")
		(net "DELTA_L_85_10INCH_IN3_DN")
	)
	(segment
		(start 234.935014 7.064248)
		(end 233.898948 1.187704)
		(width 0.14732)
		(layer "In6.Cu")
		(net "DELTA_L_85_10INCH_IN3_DN")
	)
	(segment
		(start 192.01257 0.82169)
		(end 193.267076 7.934452)
		(width 0.14732)
		(layer "In6.Cu")
		(net "DELTA_L_85_10INCH_IN3_DN")
	)
	(segment
		(start 214.231982 0.993902)
		(end 215.590374 0.75438)
		(width 0.14732)
		(layer "In6.Cu")
		(net "DELTA_L_85_10INCH_IN3_DN")
	)
	(segment
		(start 235.547662 0.896874)
		(end 236.69244 7.389368)
		(width 0.14732)
		(layer "In6.Cu")
		(net "DELTA_L_85_10INCH_IN3_DN")
	)
	(segment
		(start 230.972868 7.03199)
		(end 229.93604 1.150874)
		(width 0.14732)
		(layer "In6.Cu")
		(net "DELTA_L_85_10INCH_IN3_DN")
	)
	(segment
		(start 206.318612 0.990346)
		(end 207.67675 0.75057)
		(width 0.14732)
		(layer "In6.Cu")
		(net "DELTA_L_85_10INCH_IN3_DN")
	)
	(segment
		(start 210.266788 0.944372)
		(end 211.62518 0.70485)
		(width 0.14732)
		(layer "In6.Cu")
		(net "DELTA_L_85_10INCH_IN3_DN")
	)
	(segment
		(start 199.154542 7.862824)
		(end 199.404732 7.506208)
		(width 0.14732)
		(layer "In6.Cu")
		(net "DELTA_L_85_10INCH_IN3_DN")
	)
	(segment
		(start 203.36383 7.518654)
		(end 202.23607 1.122934)
		(width 0.14732)
		(layer "In6.Cu")
		(net "DELTA_L_85_10INCH_IN3_DN")
	)
	(segment
		(start 223.667828 0.838454)
		(end 224.826576 7.409942)
		(width 0.14732)
		(layer "In6.Cu")
		(net "DELTA_L_85_10INCH_IN3_DN")
	)
	(segment
		(start 212.963506 7.44728)
		(end 213.320122 7.69747)
		(width 0.14732)
		(layer "In6.Cu")
		(net "DELTA_L_85_10INCH_IN3_DN")
	)
	(segment
		(start 219.552774 0.786892)
		(end 219.722954 0.906018)
		(width 0.14732)
		(layer "In6.Cu")
		(net "DELTA_L_85_10INCH_IN3_DN")
	)
	(segment
		(start 209.426302 8.054086)
		(end 211.008722 7.775194)
		(width 0.14732)
		(layer "In6.Cu")
		(net "DELTA_L_85_10INCH_IN3_DN")
	)
	(segment
		(start 206.199232 1.16078)
		(end 206.318612 0.990346)
		(width 0.14732)
		(layer "In6.Cu")
		(net "DELTA_L_85_10INCH_IN3_DN")
	)
	(segment
		(start 197.57263 8.14197)
		(end 199.154542 7.862824)
		(width 0.14732)
		(layer "In6.Cu")
		(net "DELTA_L_85_10INCH_IN3_DN")
	)
	(segment
		(start 224.826576 7.409942)
		(end 225.182684 7.659878)
		(width 0.14732)
		(layer "In6.Cu")
		(net "DELTA_L_85_10INCH_IN3_DN")
	)
	(segment
		(start 241.926872 0.993902)
		(end 243.285264 0.75438)
		(width 0.14732)
		(layer "In6.Cu")
		(net "DELTA_L_85_10INCH_IN3_DN")
	)
	(segment
		(start 190.364618 1.112266)
		(end 190.483998 0.941832)
		(width 0.14732)
		(layer "In6.Cu")
		(net "DELTA_L_85_10INCH_IN3_DN")
	)
	(segment
		(start 237.961678 0.94361)
		(end 239.320324 0.704088)
		(width 0.14732)
		(layer "In6.Cu")
		(net "DELTA_L_85_10INCH_IN3_DN")
	)
	(segment
		(start 230.722932 7.388098)
		(end 230.972868 7.03199)
		(width 0.14732)
		(layer "In6.Cu")
		(net "DELTA_L_85_10INCH_IN3_DN")
	)
	(segment
		(start 211.258658 7.417816)
		(end 210.147408 1.114806)
		(width 0.14732)
		(layer "In6.Cu")
		(net "DELTA_L_85_10INCH_IN3_DN")
	)
	(segment
		(start 195.962778 0.785368)
		(end 197.215506 7.892288)
		(width 0.14732)
		(layer "In6.Cu")
		(net "DELTA_L_85_10INCH_IN3_DN")
	)
	(segment
		(start 193.267076 7.934452)
		(end 193.623692 8.184642)
		(width 0.14732)
		(layer "In6.Cu")
		(net "DELTA_L_85_10INCH_IN3_DN")
	)
	(segment
		(start 195.205858 7.90575)
		(end 195.456048 7.549134)
		(width 0.14732)
		(layer "In6.Cu")
		(net "DELTA_L_85_10INCH_IN3_DN")
	)
	(segment
		(start 199.936608 0.883412)
		(end 201.174604 7.904734)
		(width 0.14732)
		(layer "In6.Cu")
		(net "DELTA_L_85_10INCH_IN3_DN")
	)
	(segment
		(start 195.792598 0.665988)
		(end 195.962778 0.785368)
		(width 0.14732)
		(layer "In6.Cu")
		(net "DELTA_L_85_10INCH_IN3_DN")
	)
	(segment
		(start 223.069404 7.085076)
		(end 222.019114 1.129284)
		(width 0.14732)
		(layer "In6.Cu")
		(net "DELTA_L_85_10INCH_IN3_DN")
	)
	(segment
		(start 215.590374 0.75438)
		(end 215.760554 0.87376)
		(width 0.14732)
		(layer "In6.Cu")
		(net "DELTA_L_85_10INCH_IN3_DN")
	)
	(segment
		(start 218.856052 7.403084)
		(end 219.106242 7.046468)
		(width 0.14732)
		(layer "In6.Cu")
		(net "DELTA_L_85_10INCH_IN3_DN")
	)
	(segment
		(start 207.847184 0.86995)
		(end 209.069686 7.803896)
		(width 0.14732)
		(layer "In6.Cu")
		(net "DELTA_L_85_10INCH_IN3_DN")
	)
	(segment
		(start 233.898948 1.187704)
		(end 234.018328 1.01727)
		(width 0.14732)
		(layer "In6.Cu")
		(net "DELTA_L_85_10INCH_IN3_DN")
	)
	(segment
		(start 226.765104 7.380732)
		(end 227.01504 7.024624)
		(width 0.14732)
		(layer "In6.Cu")
		(net "DELTA_L_85_10INCH_IN3_DN")
	)
	(segment
		(start 227.01504 7.024624)
		(end 225.986086 1.18872)
		(width 0.14732)
		(layer "In6.Cu")
		(net "DELTA_L_85_10INCH_IN3_DN")
	)
	(segment
		(start 219.722954 0.906018)
		(end 220.880686 7.470902)
		(width 0.14732)
		(layer "In6.Cu")
		(net "DELTA_L_85_10INCH_IN3_DN")
	)
	(segment
		(start 216.917524 7.432294)
		(end 217.27414 7.68223)
		(width 0.14732)
		(layer "In6.Cu")
		(net "DELTA_L_85_10INCH_IN3_DN")
	)
	(segment
		(start 207.297782 7.392416)
		(end 206.199232 1.16078)
		(width 0.14732)
		(layer "In6.Cu")
		(net "DELTA_L_85_10INCH_IN3_DN")
	)
	(segment
		(start 214.112602 1.164336)
		(end 214.231982 0.993902)
		(width 0.14732)
		(layer "In6.Cu")
		(net "DELTA_L_85_10INCH_IN3_DN")
	)
	(segment
		(start 240.647728 7.383272)
		(end 241.00409 7.633208)
		(width 0.14732)
		(layer "In6.Cu")
		(net "DELTA_L_85_10INCH_IN3_DN")
	)
	(segment
		(start 229.140512 7.667244)
		(end 230.722932 7.388098)
		(width 0.14732)
		(layer "In6.Cu")
		(net "DELTA_L_85_10INCH_IN3_DN")
	)
	(segment
		(start 328.414888 5.213858)
		(end 327.733914 5.031994)
		(width 0.13208)
		(layer "F.Cu")
		(net "DELTA_L_85_10INCH_IN2_DP")
	)
	(segment
		(start 261.557008 5.213858)
		(end 262.237982 5.031994)
		(width 0.13208)
		(layer "F.Cu")
		(net "DELTA_L_85_10INCH_IN2_DP")
	)
	(segment
		(start 322.79209 5.326634)
		(end 327.439274 5.326634)
		(width 0.14732)
		(layer "In4.Cu")
		(net "DELTA_L_85_10INCH_IN2_DP")
	)
	(segment
		(start 278.44623 1.414526)
		(end 279.62733 8.11276)
		(width 0.14732)
		(layer "In4.Cu")
		(net "DELTA_L_85_10INCH_IN2_DP")
	)
	(segment
		(start 285.99257 1.108202)
		(end 286.349186 1.358138)
		(width 0.14732)
		(layer "In4.Cu")
		(net "DELTA_L_85_10INCH_IN2_DP")
	)
	(segment
		(start 317.653416 1.160272)
		(end 318.010286 1.410208)
		(width 0.14732)
		(layer "In4.Cu")
		(net "DELTA_L_85_10INCH_IN2_DP")
	)
	(segment
		(start 273.372326 7.876794)
		(end 272.287746 1.725168)
		(width 0.14732)
		(layer "In4.Cu")
		(net "DELTA_L_85_10INCH_IN2_DP")
	)
	(segment
		(start 295.623234 8.228838)
		(end 296.981372 7.989316)
		(width 0.14732)
		(layer "In4.Cu")
		(net "DELTA_L_85_10INCH_IN2_DP")
	)
	(segment
		(start 289.190684 7.834122)
		(end 288.126678 1.799336)
		(width 0.14732)
		(layer "In4.Cu")
		(net "DELTA_L_85_10INCH_IN2_DP")
	)
	(segment
		(start 277.220172 8.109966)
		(end 277.339806 7.939278)
		(width 0.14732)
		(layer "In4.Cu")
		(net "DELTA_L_85_10INCH_IN2_DP")
	)
	(segment
		(start 289.95878 1.163828)
		(end 290.315396 1.41351)
		(width 0.14732)
		(layer "In4.Cu")
		(net "DELTA_L_85_10INCH_IN2_DP")
	)
	(segment
		(start 301.843694 1.25349)
		(end 302.200818 1.503172)
		(width 0.14732)
		(layer "In4.Cu")
		(net "DELTA_L_85_10INCH_IN2_DP")
	)
	(segment
		(start 312.125614 1.502918)
		(end 313.708034 1.223772)
		(width 0.14732)
		(layer "In4.Cu")
		(net "DELTA_L_85_10INCH_IN2_DP")
	)
	(segment
		(start 284.41015 1.387348)
		(end 285.99257 1.108202)
		(width 0.14732)
		(layer "In4.Cu")
		(net "DELTA_L_85_10INCH_IN2_DP")
	)
	(segment
		(start 308.985158 7.903972)
		(end 307.916834 1.844802)
		(width 0.14732)
		(layer "In4.Cu")
		(net "DELTA_L_85_10INCH_IN2_DP")
	)
	(segment
		(start 321.955922 1.348232)
		(end 322.63334 5.193284)
		(width 0.14732)
		(layer "In4.Cu")
		(net "DELTA_L_85_10INCH_IN2_DP")
	)
	(segment
		(start 287.542224 8.124698)
		(end 287.712912 8.244332)
		(width 0.14732)
		(layer "In4.Cu")
		(net "DELTA_L_85_10INCH_IN2_DP")
	)
	(segment
		(start 267.75918 8.120126)
		(end 267.929868 8.23976)
		(width 0.14732)
		(layer "In4.Cu")
		(net "DELTA_L_85_10INCH_IN2_DP")
	)
	(segment
		(start 287.712912 8.244332)
		(end 289.07105 8.00481)
		(width 0.14732)
		(layer "In4.Cu")
		(net "DELTA_L_85_10INCH_IN2_DP")
	)
	(segment
		(start 274.119848 1.08966)
		(end 274.476464 1.339342)
		(width 0.14732)
		(layer "In4.Cu")
		(net "DELTA_L_85_10INCH_IN2_DP")
	)
	(segment
		(start 298.242482 1.49352)
		(end 299.432472 8.242808)
		(width 0.14732)
		(layer "In4.Cu")
		(net "DELTA_L_85_10INCH_IN2_DP")
	)
	(segment
		(start 294.273478 1.422908)
		(end 295.452546 8.109458)
		(width 0.14732)
		(layer "In4.Cu")
		(net "DELTA_L_85_10INCH_IN2_DP")
	)
	(segment
		(start 270.156432 1.051306)
		(end 270.513048 1.300988)
		(width 0.14732)
		(layer "In4.Cu")
		(net "DELTA_L_85_10INCH_IN2_DP")
	)
	(segment
		(start 281.27579 7.82193)
		(end 280.200354 1.723136)
		(width 0.14732)
		(layer "In4.Cu")
		(net "DELTA_L_85_10INCH_IN2_DP")
	)
	(segment
		(start 296.3037 1.522984)
		(end 297.885866 1.243838)
		(width 0.14732)
		(layer "In4.Cu")
		(net "DELTA_L_85_10INCH_IN2_DP")
	)
	(segment
		(start 309.74919 1.208532)
		(end 310.105806 1.458722)
		(width 0.14732)
		(layer "In4.Cu")
		(net "DELTA_L_85_10INCH_IN2_DP")
	)
	(segment
		(start 271.894554 8.287004)
		(end 273.252692 8.047482)
		(width 0.14732)
		(layer "In4.Cu")
		(net "DELTA_L_85_10INCH_IN2_DP")
	)
	(segment
		(start 303.962308 1.856994)
		(end 304.21199 1.500124)
		(width 0.14732)
		(layer "In4.Cu")
		(net "DELTA_L_85_10INCH_IN2_DP")
	)
	(segment
		(start 316.897004 7.897114)
		(end 315.821314 1.79578)
		(width 0.14732)
		(layer "In4.Cu")
		(net "DELTA_L_85_10INCH_IN2_DP")
	)
	(segment
		(start 268.32433 1.686814)
		(end 268.574012 1.330198)
		(width 0.14732)
		(layer "In4.Cu")
		(net "DELTA_L_85_10INCH_IN2_DP")
	)
	(segment
		(start 290.315396 1.41351)
		(end 291.508942 8.18261)
		(width 0.14732)
		(layer "In4.Cu")
		(net "DELTA_L_85_10INCH_IN2_DP")
	)
	(segment
		(start 306.151534 1.471676)
		(end 307.337206 8.194294)
		(width 0.14732)
		(layer "In4.Cu")
		(net "DELTA_L_85_10INCH_IN2_DP")
	)
	(segment
		(start 319.197228 8.141208)
		(end 319.367408 8.260588)
		(width 0.14732)
		(layer "In4.Cu")
		(net "DELTA_L_85_10INCH_IN2_DP")
	)
	(segment
		(start 296.981372 7.989316)
		(end 297.101006 7.818628)
		(width 0.14732)
		(layer "In4.Cu")
		(net "DELTA_L_85_10INCH_IN2_DP")
	)
	(segment
		(start 297.885866 1.243838)
		(end 298.242482 1.49352)
		(width 0.14732)
		(layer "In4.Cu")
		(net "DELTA_L_85_10INCH_IN2_DP")
	)
	(segment
		(start 281.156156 7.992618)
		(end 281.27579 7.82193)
		(width 0.14732)
		(layer "In4.Cu")
		(net "DELTA_L_85_10INCH_IN2_DP")
	)
	(segment
		(start 297.101006 7.818628)
		(end 296.053764 1.879854)
		(width 0.14732)
		(layer "In4.Cu")
		(net "DELTA_L_85_10INCH_IN2_DP")
	)
	(segment
		(start 275.691346 8.230108)
		(end 275.862034 8.349488)
		(width 0.14732)
		(layer "In4.Cu")
		(net "DELTA_L_85_10INCH_IN2_DP")
	)
	(segment
		(start 285.130494 8.093964)
		(end 285.250128 7.92353)
		(width 0.14732)
		(layer "In4.Cu")
		(net "DELTA_L_85_10INCH_IN2_DP")
	)
	(segment
		(start 284.160468 1.743964)
		(end 284.41015 1.387348)
		(width 0.14732)
		(layer "In4.Cu")
		(net "DELTA_L_85_10INCH_IN2_DP")
	)
	(segment
		(start 278.089614 1.164844)
		(end 278.44623 1.414526)
		(width 0.14732)
		(layer "In4.Cu")
		(net "DELTA_L_85_10INCH_IN2_DP")
	)
	(segment
		(start 315.419232 8.30707)
		(end 316.777624 8.067802)
		(width 0.14732)
		(layer "In4.Cu")
		(net "DELTA_L_85_10INCH_IN2_DP")
	)
	(segment
		(start 320.7258 8.02132)
		(end 320.84518 7.850632)
		(width 0.14732)
		(layer "In4.Cu")
		(net "DELTA_L_85_10INCH_IN2_DP")
	)
	(segment
		(start 312.93943 7.891272)
		(end 311.875932 1.859534)
		(width 0.14732)
		(layer "In4.Cu")
		(net "DELTA_L_85_10INCH_IN2_DP")
	)
	(segment
		(start 299.602906 8.362188)
		(end 300.961298 8.12292)
		(width 0.14732)
		(layer "In4.Cu")
		(net "DELTA_L_85_10INCH_IN2_DP")
	)
	(segment
		(start 313.708034 1.223772)
		(end 314.065158 1.473454)
		(width 0.14732)
		(layer "In4.Cu")
		(net "DELTA_L_85_10INCH_IN2_DP")
	)
	(segment
		(start 270.513048 1.300988)
		(end 271.723866 8.16737)
		(width 0.14732)
		(layer "In4.Cu")
		(net "DELTA_L_85_10INCH_IN2_DP")
	)
	(segment
		(start 272.537428 1.368552)
		(end 274.119848 1.08966)
		(width 0.14732)
		(layer "In4.Cu")
		(net "DELTA_L_85_10INCH_IN2_DP")
	)
	(segment
		(start 300.961298 8.12292)
		(end 301.080678 7.952232)
		(width 0.14732)
		(layer "In4.Cu")
		(net "DELTA_L_85_10INCH_IN2_DP")
	)
	(segment
		(start 282.389072 1.337056)
		(end 283.601414 8.213852)
		(width 0.14732)
		(layer "In4.Cu")
		(net "DELTA_L_85_10INCH_IN2_DP")
	)
	(segment
		(start 268.574012 1.330198)
		(end 270.156432 1.051306)
		(width 0.14732)
		(layer "In4.Cu")
		(net "DELTA_L_85_10INCH_IN2_DP")
	)
	(segment
		(start 314.065158 1.473454)
		(end 315.249052 8.18769)
		(width 0.14732)
		(layer "In4.Cu")
		(net "DELTA_L_85_10INCH_IN2_DP")
	)
	(segment
		(start 280.450036 1.36652)
		(end 282.032456 1.087374)
		(width 0.14732)
		(layer "In4.Cu")
		(net "DELTA_L_85_10INCH_IN2_DP")
	)
	(segment
		(start 293.037768 8.062722)
		(end 293.157402 7.892034)
		(width 0.14732)
		(layer "In4.Cu")
		(net "DELTA_L_85_10INCH_IN2_DP")
	)
	(segment
		(start 310.105806 1.458722)
		(end 311.291224 8.181848)
		(width 0.14732)
		(layer "In4.Cu")
		(net "DELTA_L_85_10INCH_IN2_DP")
	)
	(segment
		(start 288.126678 1.799336)
		(end 288.37636 1.44272)
		(width 0.14732)
		(layer "In4.Cu")
		(net "DELTA_L_85_10INCH_IN2_DP")
	)
	(segment
		(start 304.90795 8.066786)
		(end 305.02733 7.896606)
		(width 0.14732)
		(layer "In4.Cu")
		(net "DELTA_L_85_10INCH_IN2_DP")
	)
	(segment
		(start 267.312902 5.588254)
		(end 267.75918 8.120126)
		(width 0.14732)
		(layer "In4.Cu")
		(net "DELTA_L_85_10INCH_IN2_DP")
	)
	(segment
		(start 319.766696 1.733804)
		(end 320.016378 1.377442)
		(width 0.14732)
		(layer "In4.Cu")
		(net "DELTA_L_85_10INCH_IN2_DP")
	)
	(segment
		(start 321.598544 1.098296)
		(end 321.955922 1.348232)
		(width 0.14732)
		(layer "In4.Cu")
		(net "DELTA_L_85_10INCH_IN2_DP")
	)
	(segment
		(start 269.40764 7.829804)
		(end 268.32433 1.686814)
		(width 0.14732)
		(layer "In4.Cu")
		(net "DELTA_L_85_10INCH_IN2_DP")
	)
	(segment
		(start 296.053764 1.879854)
		(end 296.3037 1.522984)
		(width 0.14732)
		(layer "In4.Cu")
		(net "DELTA_L_85_10INCH_IN2_DP")
	)
	(segment
		(start 293.157402 7.892034)
		(end 292.08476 1.808988)
		(width 0.14732)
		(layer "In4.Cu")
		(net "DELTA_L_85_10INCH_IN2_DP")
	)
	(segment
		(start 322.63334 5.193284)
		(end 322.79209 5.326634)
		(width 0.14732)
		(layer "In4.Cu")
		(net "DELTA_L_85_10INCH_IN2_DP")
	)
	(segment
		(start 303.549558 8.306308)
		(end 304.90795 8.066786)
		(width 0.14732)
		(layer "In4.Cu")
		(net "DELTA_L_85_10INCH_IN2_DP")
	)
	(segment
		(start 283.772356 8.333232)
		(end 285.130494 8.093964)
		(width 0.14732)
		(layer "In4.Cu")
		(net "DELTA_L_85_10INCH_IN2_DP")
	)
	(segment
		(start 279.798018 8.23214)
		(end 281.156156 7.992618)
		(width 0.14732)
		(layer "In4.Cu")
		(net "DELTA_L_85_10INCH_IN2_DP")
	)
	(segment
		(start 289.07105 8.00481)
		(end 289.190684 7.834122)
		(width 0.14732)
		(layer "In4.Cu")
		(net "DELTA_L_85_10INCH_IN2_DP")
	)
	(segment
		(start 282.032456 1.087374)
		(end 282.389072 1.337056)
		(width 0.14732)
		(layer "In4.Cu")
		(net "DELTA_L_85_10INCH_IN2_DP")
	)
	(segment
		(start 291.67963 8.302244)
		(end 293.037768 8.062722)
		(width 0.14732)
		(layer "In4.Cu")
		(net "DELTA_L_85_10INCH_IN2_DP")
	)
	(segment
		(start 286.349186 1.358138)
		(end 287.542224 8.124698)
		(width 0.14732)
		(layer "In4.Cu")
		(net "DELTA_L_85_10INCH_IN2_DP")
	)
	(segment
		(start 312.82005 8.061452)
		(end 312.93943 7.891272)
		(width 0.14732)
		(layer "In4.Cu")
		(net "DELTA_L_85_10INCH_IN2_DP")
	)
	(segment
		(start 316.777624 8.067802)
		(end 316.897004 7.897114)
		(width 0.14732)
		(layer "In4.Cu")
		(net "DELTA_L_85_10INCH_IN2_DP")
	)
	(segment
		(start 300.261528 1.532636)
		(end 301.843694 1.25349)
		(width 0.14732)
		(layer "In4.Cu")
		(net "DELTA_L_85_10INCH_IN2_DP")
	)
	(segment
		(start 320.84518 7.850632)
		(end 319.766696 1.733804)
		(width 0.14732)
		(layer "In4.Cu")
		(net "DELTA_L_85_10INCH_IN2_DP")
	)
	(segment
		(start 316.070996 1.439418)
		(end 317.653416 1.160272)
		(width 0.14732)
		(layer "In4.Cu")
		(net "DELTA_L_85_10INCH_IN2_DP")
	)
	(segment
		(start 292.334442 1.452118)
		(end 293.916862 1.173226)
		(width 0.14732)
		(layer "In4.Cu")
		(net "DELTA_L_85_10INCH_IN2_DP")
	)
	(segment
		(start 307.916834 1.844802)
		(end 308.166516 1.487678)
		(width 0.14732)
		(layer "In4.Cu")
		(net "DELTA_L_85_10INCH_IN2_DP")
	)
	(segment
		(start 299.432472 8.242808)
		(end 299.602906 8.362188)
		(width 0.14732)
		(layer "In4.Cu")
		(net "DELTA_L_85_10INCH_IN2_DP")
	)
	(segment
		(start 307.337206 8.194294)
		(end 307.507386 8.313674)
		(width 0.14732)
		(layer "In4.Cu")
		(net "DELTA_L_85_10INCH_IN2_DP")
	)
	(segment
		(start 311.875932 1.859534)
		(end 312.125614 1.502918)
		(width 0.14732)
		(layer "In4.Cu")
		(net "DELTA_L_85_10INCH_IN2_DP")
	)
	(segment
		(start 301.080678 7.952232)
		(end 300.011592 1.889252)
		(width 0.14732)
		(layer "In4.Cu")
		(net "DELTA_L_85_10INCH_IN2_DP")
	)
	(segment
		(start 295.452546 8.109458)
		(end 295.623234 8.228838)
		(width 0.14732)
		(layer "In4.Cu")
		(net "DELTA_L_85_10INCH_IN2_DP")
	)
	(segment
		(start 311.461658 8.301228)
		(end 312.82005 8.061452)
		(width 0.14732)
		(layer "In4.Cu")
		(net "DELTA_L_85_10INCH_IN2_DP")
	)
	(segment
		(start 291.508942 8.18261)
		(end 291.67963 8.302244)
		(width 0.14732)
		(layer "In4.Cu")
		(net "DELTA_L_85_10INCH_IN2_DP")
	)
	(segment
		(start 308.166516 1.487678)
		(end 309.74919 1.208532)
		(width 0.14732)
		(layer "In4.Cu")
		(net "DELTA_L_85_10INCH_IN2_DP")
	)
	(segment
		(start 274.476464 1.339342)
		(end 275.691346 8.230108)
		(width 0.14732)
		(layer "In4.Cu")
		(net "DELTA_L_85_10INCH_IN2_DP")
	)
	(segment
		(start 300.011592 1.889252)
		(end 300.261528 1.532636)
		(width 0.14732)
		(layer "In4.Cu")
		(net "DELTA_L_85_10INCH_IN2_DP")
	)
	(segment
		(start 276.507194 1.44399)
		(end 278.089614 1.164844)
		(width 0.14732)
		(layer "In4.Cu")
		(net "DELTA_L_85_10INCH_IN2_DP")
	)
	(segment
		(start 319.367408 8.260588)
		(end 320.7258 8.02132)
		(width 0.14732)
		(layer "In4.Cu")
		(net "DELTA_L_85_10INCH_IN2_DP")
	)
	(segment
		(start 267.929868 8.23976)
		(end 269.288006 8.000238)
		(width 0.14732)
		(layer "In4.Cu")
		(net "DELTA_L_85_10INCH_IN2_DP")
	)
	(segment
		(start 285.250128 7.92353)
		(end 284.160468 1.743964)
		(width 0.14732)
		(layer "In4.Cu")
		(net "DELTA_L_85_10INCH_IN2_DP")
	)
	(segment
		(start 293.916862 1.173226)
		(end 294.273478 1.422908)
		(width 0.14732)
		(layer "In4.Cu")
		(net "DELTA_L_85_10INCH_IN2_DP")
	)
	(segment
		(start 307.507386 8.313674)
		(end 308.865778 8.074152)
		(width 0.14732)
		(layer "In4.Cu")
		(net "DELTA_L_85_10INCH_IN2_DP")
	)
	(segment
		(start 262.532622 5.326634)
		(end 267.00099 5.326634)
		(width 0.14732)
		(layer "In4.Cu")
		(net "DELTA_L_85_10INCH_IN2_DP")
	)
	(segment
		(start 304.21199 1.500124)
		(end 305.794664 1.221232)
		(width 0.14732)
		(layer "In4.Cu")
		(net "DELTA_L_85_10INCH_IN2_DP")
	)
	(segment
		(start 311.291224 8.181848)
		(end 311.461658 8.301228)
		(width 0.14732)
		(layer "In4.Cu")
		(net "DELTA_L_85_10INCH_IN2_DP")
	)
	(segment
		(start 272.287746 1.725168)
		(end 272.537428 1.368552)
		(width 0.14732)
		(layer "In4.Cu")
		(net "DELTA_L_85_10INCH_IN2_DP")
	)
	(segment
		(start 276.257512 1.800606)
		(end 276.507194 1.44399)
		(width 0.14732)
		(layer "In4.Cu")
		(net "DELTA_L_85_10INCH_IN2_DP")
	)
	(segment
		(start 267.00099 5.326634)
		(end 267.312902 5.588254)
		(width 0.14732)
		(layer "In4.Cu")
		(net "DELTA_L_85_10INCH_IN2_DP")
	)
	(segment
		(start 288.37636 1.44272)
		(end 289.95878 1.163828)
		(width 0.14732)
		(layer "In4.Cu")
		(net "DELTA_L_85_10INCH_IN2_DP")
	)
	(segment
		(start 292.08476 1.808988)
		(end 292.334442 1.452118)
		(width 0.14732)
		(layer "In4.Cu")
		(net "DELTA_L_85_10INCH_IN2_DP")
	)
	(segment
		(start 327.439274 5.326634)
		(end 327.733914 5.031994)
		(width 0.14732)
		(layer "In4.Cu")
		(net "DELTA_L_85_10INCH_IN2_DP")
	)
	(segment
		(start 273.252692 8.047482)
		(end 273.372326 7.876794)
		(width 0.14732)
		(layer "In4.Cu")
		(net "DELTA_L_85_10INCH_IN2_DP")
	)
	(segment
		(start 320.016378 1.377442)
		(end 321.598544 1.098296)
		(width 0.14732)
		(layer "In4.Cu")
		(net "DELTA_L_85_10INCH_IN2_DP")
	)
	(segment
		(start 280.200354 1.723136)
		(end 280.450036 1.36652)
		(width 0.14732)
		(layer "In4.Cu")
		(net "DELTA_L_85_10INCH_IN2_DP")
	)
	(segment
		(start 302.200818 1.503172)
		(end 303.379378 8.186928)
		(width 0.14732)
		(layer "In4.Cu")
		(net "DELTA_L_85_10INCH_IN2_DP")
	)
	(segment
		(start 305.02733 7.896606)
		(end 303.962308 1.856994)
		(width 0.14732)
		(layer "In4.Cu")
		(net "DELTA_L_85_10INCH_IN2_DP")
	)
	(segment
		(start 303.379378 8.186928)
		(end 303.549558 8.306308)
		(width 0.14732)
		(layer "In4.Cu")
		(net "DELTA_L_85_10INCH_IN2_DP")
	)
	(segment
		(start 279.62733 8.11276)
		(end 279.798018 8.23214)
		(width 0.14732)
		(layer "In4.Cu")
		(net "DELTA_L_85_10INCH_IN2_DP")
	)
	(segment
		(start 305.794664 1.221232)
		(end 306.151534 1.471676)
		(width 0.14732)
		(layer "In4.Cu")
		(net "DELTA_L_85_10INCH_IN2_DP")
	)
	(segment
		(start 262.237982 5.031994)
		(end 262.532622 5.326634)
		(width 0.14732)
		(layer "In4.Cu")
		(net "DELTA_L_85_10INCH_IN2_DP")
	)
	(segment
		(start 283.601414 8.213852)
		(end 283.772356 8.333232)
		(width 0.14732)
		(layer "In4.Cu")
		(net "DELTA_L_85_10INCH_IN2_DP")
	)
	(segment
		(start 277.339806 7.939278)
		(end 276.257512 1.800606)
		(width 0.14732)
		(layer "In4.Cu")
		(net "DELTA_L_85_10INCH_IN2_DP")
	)
	(segment
		(start 318.010286 1.410208)
		(end 319.197228 8.141208)
		(width 0.14732)
		(layer "In4.Cu")
		(net "DELTA_L_85_10INCH_IN2_DP")
	)
	(segment
		(start 275.862034 8.349488)
		(end 277.220172 8.109966)
		(width 0.14732)
		(layer "In4.Cu")
		(net "DELTA_L_85_10INCH_IN2_DP")
	)
	(segment
		(start 269.288006 8.000238)
		(end 269.40764 7.829804)
		(width 0.14732)
		(layer "In4.Cu")
		(net "DELTA_L_85_10INCH_IN2_DP")
	)
	(segment
		(start 315.821314 1.79578)
		(end 316.070996 1.439418)
		(width 0.14732)
		(layer "In4.Cu")
		(net "DELTA_L_85_10INCH_IN2_DP")
	)
	(segment
		(start 308.865778 8.074152)
		(end 308.985158 7.903972)
		(width 0.14732)
		(layer "In4.Cu")
		(net "DELTA_L_85_10INCH_IN2_DP")
	)
	(segment
		(start 271.723866 8.16737)
		(end 271.894554 8.287004)
		(width 0.14732)
		(layer "In4.Cu")
		(net "DELTA_L_85_10INCH_IN2_DP")
	)
	(segment
		(start 315.249052 8.18769)
		(end 315.419232 8.30707)
		(width 0.14732)
		(layer "In4.Cu")
		(net "DELTA_L_85_10INCH_IN2_DP")
	)
	(segment
		(start 328.414888 5.71373)
		(end 327.733914 5.895594)
		(width 0.13208)
		(layer "F.Cu")
		(net "DELTA_L_85_10INCH_IN2_DN")
	)
	(segment
		(start 261.557008 5.71373)
		(end 262.237982 5.895594)
		(width 0.13208)
		(layer "F.Cu")
		(net "DELTA_L_85_10INCH_IN2_DN")
	)
	(segment
		(start 309.275226 7.968488)
		(end 308.206902 1.909064)
		(width 0.14732)
		(layer "In4.Cu")
		(net "DELTA_L_85_10INCH_IN2_DN")
	)
	(segment
		(start 313.229498 7.955788)
		(end 312.166 1.923796)
		(width 0.14732)
		(layer "In4.Cu")
		(net "DELTA_L_85_10INCH_IN2_DN")
	)
	(segment
		(start 267.508482 8.279638)
		(end 267.865606 8.529828)
		(width 0.14732)
		(layer "In4.Cu")
		(net "DELTA_L_85_10INCH_IN2_DN")
	)
	(segment
		(start 289.480752 7.898638)
		(end 288.416746 1.863598)
		(width 0.14732)
		(layer "In4.Cu")
		(net "DELTA_L_85_10INCH_IN2_DN")
	)
	(segment
		(start 289.230562 8.255254)
		(end 289.480752 7.898638)
		(width 0.14732)
		(layer "In4.Cu")
		(net "DELTA_L_85_10INCH_IN2_DN")
	)
	(segment
		(start 305.730148 1.5113)
		(end 305.900836 1.631188)
		(width 0.14732)
		(layer "In4.Cu")
		(net "DELTA_L_85_10INCH_IN2_DN")
	)
	(segment
		(start 269.447518 8.250936)
		(end 269.697708 7.89432)
		(width 0.14732)
		(layer "In4.Cu")
		(net "DELTA_L_85_10INCH_IN2_DN")
	)
	(segment
		(start 312.28538 1.753616)
		(end 313.643772 1.51384)
		(width 0.14732)
		(layer "In4.Cu")
		(net "DELTA_L_85_10INCH_IN2_DN")
	)
	(segment
		(start 272.577814 1.78943)
		(end 272.697194 1.61925)
		(width 0.14732)
		(layer "In4.Cu")
		(net "DELTA_L_85_10INCH_IN2_DN")
	)
	(segment
		(start 305.067462 8.317484)
		(end 305.317398 7.961122)
		(width 0.14732)
		(layer "In4.Cu")
		(net "DELTA_L_85_10INCH_IN2_DN")
	)
	(segment
		(start 319.302892 8.550656)
		(end 320.885566 8.272018)
		(width 0.14732)
		(layer "In4.Cu")
		(net "DELTA_L_85_10INCH_IN2_DN")
	)
	(segment
		(start 279.733756 8.522208)
		(end 281.315668 8.243062)
		(width 0.14732)
		(layer "In4.Cu")
		(net "DELTA_L_85_10INCH_IN2_DN")
	)
	(segment
		(start 297.391074 7.883144)
		(end 296.343832 1.944116)
		(width 0.14732)
		(layer "In4.Cu")
		(net "DELTA_L_85_10INCH_IN2_DN")
	)
	(segment
		(start 316.230508 1.689862)
		(end 317.589154 1.45034)
		(width 0.14732)
		(layer "In4.Cu")
		(net "DELTA_L_85_10INCH_IN2_DN")
	)
	(segment
		(start 307.44287 8.603742)
		(end 309.02529 8.32485)
		(width 0.14732)
		(layer "In4.Cu")
		(net "DELTA_L_85_10INCH_IN2_DN")
	)
	(segment
		(start 320.056764 1.79832)
		(end 320.176144 1.62814)
		(width 0.14732)
		(layer "In4.Cu")
		(net "DELTA_L_85_10INCH_IN2_DN")
	)
	(segment
		(start 305.900836 1.631188)
		(end 307.086762 8.353806)
		(width 0.14732)
		(layer "In4.Cu")
		(net "DELTA_L_85_10INCH_IN2_DN")
	)
	(segment
		(start 318.946784 8.30072)
		(end 319.302892 8.550656)
		(width 0.14732)
		(layer "In4.Cu")
		(net "DELTA_L_85_10INCH_IN2_DN")
	)
	(segment
		(start 277.379684 8.36041)
		(end 277.629874 8.003794)
		(width 0.14732)
		(layer "In4.Cu")
		(net "DELTA_L_85_10INCH_IN2_DN")
	)
	(segment
		(start 285.290006 8.344662)
		(end 285.540196 7.988046)
		(width 0.14732)
		(layer "In4.Cu")
		(net "DELTA_L_85_10INCH_IN2_DN")
	)
	(segment
		(start 301.370746 8.016494)
		(end 300.30166 1.953514)
		(width 0.14732)
		(layer "In4.Cu")
		(net "DELTA_L_85_10INCH_IN2_DN")
	)
	(segment
		(start 281.315668 8.243062)
		(end 281.565858 7.886446)
		(width 0.14732)
		(layer "In4.Cu")
		(net "DELTA_L_85_10INCH_IN2_DN")
	)
	(segment
		(start 280.490422 1.787398)
		(end 280.609802 1.617218)
		(width 0.14732)
		(layer "In4.Cu")
		(net "DELTA_L_85_10INCH_IN2_DN")
	)
	(segment
		(start 299.538644 8.652256)
		(end 301.121064 8.373618)
		(width 0.14732)
		(layer "In4.Cu")
		(net "DELTA_L_85_10INCH_IN2_DN")
	)
	(segment
		(start 280.609802 1.617218)
		(end 281.968194 1.377442)
		(width 0.14732)
		(layer "In4.Cu")
		(net "DELTA_L_85_10INCH_IN2_DN")
	)
	(segment
		(start 271.830038 8.577072)
		(end 273.412204 8.297926)
		(width 0.14732)
		(layer "In4.Cu")
		(net "DELTA_L_85_10INCH_IN2_DN")
	)
	(segment
		(start 278.025352 1.454912)
		(end 278.195532 1.574292)
		(width 0.14732)
		(layer "In4.Cu")
		(net "DELTA_L_85_10INCH_IN2_DN")
	)
	(segment
		(start 313.643772 1.51384)
		(end 313.814714 1.63322)
		(width 0.14732)
		(layer "In4.Cu")
		(net "DELTA_L_85_10INCH_IN2_DN")
	)
	(segment
		(start 283.708094 8.6233)
		(end 285.290006 8.344662)
		(width 0.14732)
		(layer "In4.Cu")
		(net "DELTA_L_85_10INCH_IN2_DN")
	)
	(segment
		(start 297.140884 8.23976)
		(end 297.391074 7.883144)
		(width 0.14732)
		(layer "In4.Cu")
		(net "DELTA_L_85_10INCH_IN2_DN")
	)
	(segment
		(start 293.44747 7.95655)
		(end 292.374828 1.87325)
		(width 0.14732)
		(layer "In4.Cu")
		(net "DELTA_L_85_10INCH_IN2_DN")
	)
	(segment
		(start 275.440648 8.389874)
		(end 275.797772 8.639556)
		(width 0.14732)
		(layer "In4.Cu")
		(net "DELTA_L_85_10INCH_IN2_DN")
	)
	(segment
		(start 303.485042 8.596376)
		(end 305.067462 8.317484)
		(width 0.14732)
		(layer "In4.Cu")
		(net "DELTA_L_85_10INCH_IN2_DN")
	)
	(segment
		(start 276.54758 1.864868)
		(end 276.66696 1.694688)
		(width 0.14732)
		(layer "In4.Cu")
		(net "DELTA_L_85_10INCH_IN2_DN")
	)
	(segment
		(start 270.09217 1.341374)
		(end 270.26235 1.460754)
		(width 0.14732)
		(layer "In4.Cu")
		(net "DELTA_L_85_10INCH_IN2_DN")
	)
	(segment
		(start 308.326282 1.738122)
		(end 309.684674 1.4986)
		(width 0.14732)
		(layer "In4.Cu")
		(net "DELTA_L_85_10INCH_IN2_DN")
	)
	(segment
		(start 309.855362 1.618234)
		(end 311.04078 8.34136)
		(width 0.14732)
		(layer "In4.Cu")
		(net "DELTA_L_85_10INCH_IN2_DN")
	)
	(segment
		(start 292.494208 1.702816)
		(end 293.8526 1.463294)
		(width 0.14732)
		(layer "In4.Cu")
		(net "DELTA_L_85_10INCH_IN2_DN")
	)
	(segment
		(start 313.814714 1.63322)
		(end 314.998608 8.347202)
		(width 0.14732)
		(layer "In4.Cu")
		(net "DELTA_L_85_10INCH_IN2_DN")
	)
	(segment
		(start 288.535872 1.693164)
		(end 288.535872 1.693418)
		(width 0.14732)
		(layer "In4.Cu")
		(net "DELTA_L_85_10INCH_IN2_DN")
	)
	(segment
		(start 293.19728 8.313166)
		(end 293.44747 7.95655)
		(width 0.14732)
		(layer "In4.Cu")
		(net "DELTA_L_85_10INCH_IN2_DN")
	)
	(segment
		(start 308.206902 1.909064)
		(end 308.326282 1.738122)
		(width 0.14732)
		(layer "In4.Cu")
		(net "DELTA_L_85_10INCH_IN2_DN")
	)
	(segment
		(start 293.8526 1.463294)
		(end 294.02278 1.582674)
		(width 0.14732)
		(layer "In4.Cu")
		(net "DELTA_L_85_10INCH_IN2_DN")
	)
	(segment
		(start 266.901168 5.600954)
		(end 267.059918 5.734304)
		(width 0.14732)
		(layer "In4.Cu")
		(net "DELTA_L_85_10INCH_IN2_DN")
	)
	(segment
		(start 311.04078 8.34136)
		(end 311.397396 8.591296)
		(width 0.14732)
		(layer "In4.Cu")
		(net "DELTA_L_85_10INCH_IN2_DN")
	)
	(segment
		(start 262.237982 5.895594)
		(end 262.532622 5.600954)
		(width 0.14732)
		(layer "In4.Cu")
		(net "DELTA_L_85_10INCH_IN2_DN")
	)
	(segment
		(start 268.733778 1.580896)
		(end 270.09217 1.341374)
		(width 0.14732)
		(layer "In4.Cu")
		(net "DELTA_L_85_10INCH_IN2_DN")
	)
	(segment
		(start 301.779432 1.543558)
		(end 301.950374 1.662938)
		(width 0.14732)
		(layer "In4.Cu")
		(net "DELTA_L_85_10INCH_IN2_DN")
	)
	(segment
		(start 307.086762 8.353806)
		(end 307.44287 8.603742)
		(width 0.14732)
		(layer "In4.Cu")
		(net "DELTA_L_85_10INCH_IN2_DN")
	)
	(segment
		(start 317.589154 1.45034)
		(end 317.759842 1.56972)
		(width 0.14732)
		(layer "In4.Cu")
		(net "DELTA_L_85_10INCH_IN2_DN")
	)
	(segment
		(start 327.439274 5.600954)
		(end 327.733914 5.895594)
		(width 0.14732)
		(layer "In4.Cu")
		(net "DELTA_L_85_10INCH_IN2_DN")
	)
	(segment
		(start 290.064698 1.573276)
		(end 291.258498 8.342122)
		(width 0.14732)
		(layer "In4.Cu")
		(net "DELTA_L_85_10INCH_IN2_DN")
	)
	(segment
		(start 322.380356 5.339334)
		(end 322.692014 5.600954)
		(width 0.14732)
		(layer "In4.Cu")
		(net "DELTA_L_85_10INCH_IN2_DN")
	)
	(segment
		(start 315.354716 8.597138)
		(end 316.93739 8.3185)
		(width 0.14732)
		(layer "In4.Cu")
		(net "DELTA_L_85_10INCH_IN2_DN")
	)
	(segment
		(start 314.998608 8.347202)
		(end 315.354716 8.597138)
		(width 0.14732)
		(layer "In4.Cu")
		(net "DELTA_L_85_10INCH_IN2_DN")
	)
	(segment
		(start 268.614398 1.751076)
		(end 268.733778 1.580896)
		(width 0.14732)
		(layer "In4.Cu")
		(net "DELTA_L_85_10INCH_IN2_DN")
	)
	(segment
		(start 295.558972 8.518906)
		(end 297.140884 8.23976)
		(width 0.14732)
		(layer "In4.Cu")
		(net "DELTA_L_85_10INCH_IN2_DN")
	)
	(segment
		(start 282.138374 1.496822)
		(end 283.35097 8.373618)
		(width 0.14732)
		(layer "In4.Cu")
		(net "DELTA_L_85_10INCH_IN2_DN")
	)
	(segment
		(start 299.182028 8.40232)
		(end 299.538644 8.652256)
		(width 0.14732)
		(layer "In4.Cu")
		(net "DELTA_L_85_10INCH_IN2_DN")
	)
	(segment
		(start 296.463212 1.773428)
		(end 297.821604 1.533906)
		(width 0.14732)
		(layer "In4.Cu")
		(net "DELTA_L_85_10INCH_IN2_DN")
	)
	(segment
		(start 297.991784 1.653286)
		(end 299.182028 8.40232)
		(width 0.14732)
		(layer "In4.Cu")
		(net "DELTA_L_85_10INCH_IN2_DN")
	)
	(segment
		(start 285.540196 7.988046)
		(end 284.450536 1.808226)
		(width 0.14732)
		(layer "In4.Cu")
		(net "DELTA_L_85_10INCH_IN2_DN")
	)
	(segment
		(start 273.662394 7.94131)
		(end 272.577814 1.78943)
		(width 0.14732)
		(layer "In4.Cu")
		(net "DELTA_L_85_10INCH_IN2_DN")
	)
	(segment
		(start 262.532622 5.600954)
		(end 266.901168 5.600954)
		(width 0.14732)
		(layer "In4.Cu")
		(net "DELTA_L_85_10INCH_IN2_DN")
	)
	(segment
		(start 269.697708 7.89432)
		(end 268.614398 1.751076)
		(width 0.14732)
		(layer "In4.Cu")
		(net "DELTA_L_85_10INCH_IN2_DN")
	)
	(segment
		(start 273.412204 8.297926)
		(end 273.662394 7.94131)
		(width 0.14732)
		(layer "In4.Cu")
		(net "DELTA_L_85_10INCH_IN2_DN")
	)
	(segment
		(start 309.02529 8.32485)
		(end 309.275226 7.968488)
		(width 0.14732)
		(layer "In4.Cu")
		(net "DELTA_L_85_10INCH_IN2_DN")
	)
	(segment
		(start 285.928308 1.39827)
		(end 286.098742 1.51765)
		(width 0.14732)
		(layer "In4.Cu")
		(net "DELTA_L_85_10INCH_IN2_DN")
	)
	(segment
		(start 288.535872 1.693418)
		(end 289.894518 1.453896)
		(width 0.14732)
		(layer "In4.Cu")
		(net "DELTA_L_85_10INCH_IN2_DN")
	)
	(segment
		(start 288.416746 1.863598)
		(end 288.535872 1.693164)
		(width 0.14732)
		(layer "In4.Cu")
		(net "DELTA_L_85_10INCH_IN2_DN")
	)
	(segment
		(start 321.135248 7.914894)
		(end 320.056764 1.79832)
		(width 0.14732)
		(layer "In4.Cu")
		(net "DELTA_L_85_10INCH_IN2_DN")
	)
	(segment
		(start 305.317398 7.961122)
		(end 304.252376 1.921256)
		(width 0.14732)
		(layer "In4.Cu")
		(net "DELTA_L_85_10INCH_IN2_DN")
	)
	(segment
		(start 274.055586 1.379728)
		(end 274.225766 1.499108)
		(width 0.14732)
		(layer "In4.Cu")
		(net "DELTA_L_85_10INCH_IN2_DN")
	)
	(segment
		(start 284.569916 1.638046)
		(end 285.928308 1.39827)
		(width 0.14732)
		(layer "In4.Cu")
		(net "DELTA_L_85_10INCH_IN2_DN")
	)
	(segment
		(start 287.291526 8.28421)
		(end 287.648396 8.5344)
		(width 0.14732)
		(layer "In4.Cu")
		(net "DELTA_L_85_10INCH_IN2_DN")
	)
	(segment
		(start 309.684674 1.4986)
		(end 309.855362 1.618234)
		(width 0.14732)
		(layer "In4.Cu")
		(net "DELTA_L_85_10INCH_IN2_DN")
	)
	(segment
		(start 312.166 1.923796)
		(end 312.28538 1.753616)
		(width 0.14732)
		(layer "In4.Cu")
		(net "DELTA_L_85_10INCH_IN2_DN")
	)
	(segment
		(start 301.121064 8.373618)
		(end 301.370746 8.016494)
		(width 0.14732)
		(layer "In4.Cu")
		(net "DELTA_L_85_10INCH_IN2_DN")
	)
	(segment
		(start 278.195532 1.574292)
		(end 279.376632 8.272526)
		(width 0.14732)
		(layer "In4.Cu")
		(net "DELTA_L_85_10INCH_IN2_DN")
	)
	(segment
		(start 279.376632 8.272526)
		(end 279.733756 8.522208)
		(width 0.14732)
		(layer "In4.Cu")
		(net "DELTA_L_85_10INCH_IN2_DN")
	)
	(segment
		(start 296.343832 1.944116)
		(end 296.463212 1.773428)
		(width 0.14732)
		(layer "In4.Cu")
		(net "DELTA_L_85_10INCH_IN2_DN")
	)
	(segment
		(start 286.098742 1.51765)
		(end 287.291526 8.28421)
		(width 0.14732)
		(layer "In4.Cu")
		(net "DELTA_L_85_10INCH_IN2_DN")
	)
	(segment
		(start 295.201848 8.269224)
		(end 295.558972 8.518906)
		(width 0.14732)
		(layer "In4.Cu")
		(net "DELTA_L_85_10INCH_IN2_DN")
	)
	(segment
		(start 316.93739 8.3185)
		(end 317.187072 7.961376)
		(width 0.14732)
		(layer "In4.Cu")
		(net "DELTA_L_85_10INCH_IN2_DN")
	)
	(segment
		(start 311.397396 8.591296)
		(end 312.979562 8.311896)
		(width 0.14732)
		(layer "In4.Cu")
		(net "DELTA_L_85_10INCH_IN2_DN")
	)
	(segment
		(start 301.950374 1.662938)
		(end 303.128934 8.34644)
		(width 0.14732)
		(layer "In4.Cu")
		(net "DELTA_L_85_10INCH_IN2_DN")
	)
	(segment
		(start 289.894518 1.453896)
		(end 290.064698 1.573276)
		(width 0.14732)
		(layer "In4.Cu")
		(net "DELTA_L_85_10INCH_IN2_DN")
	)
	(segment
		(start 300.42104 1.78308)
		(end 301.779432 1.543558)
		(width 0.14732)
		(layer "In4.Cu")
		(net "DELTA_L_85_10INCH_IN2_DN")
	)
	(segment
		(start 304.252376 1.921256)
		(end 304.371756 1.750822)
		(width 0.14732)
		(layer "In4.Cu")
		(net "DELTA_L_85_10INCH_IN2_DN")
	)
	(segment
		(start 321.705224 1.507998)
		(end 322.380356 5.339334)
		(width 0.14732)
		(layer "In4.Cu")
		(net "DELTA_L_85_10INCH_IN2_DN")
	)
	(segment
		(start 304.371756 1.750822)
		(end 305.730148 1.5113)
		(width 0.14732)
		(layer "In4.Cu")
		(net "DELTA_L_85_10INCH_IN2_DN")
	)
	(segment
		(start 283.35097 8.373618)
		(end 283.708094 8.6233)
		(width 0.14732)
		(layer "In4.Cu")
		(net "DELTA_L_85_10INCH_IN2_DN")
	)
	(segment
		(start 284.450536 1.808226)
		(end 284.569916 1.638046)
		(width 0.14732)
		(layer "In4.Cu")
		(net "DELTA_L_85_10INCH_IN2_DN")
	)
	(segment
		(start 267.865606 8.529828)
		(end 269.447518 8.250936)
		(width 0.14732)
		(layer "In4.Cu")
		(net "DELTA_L_85_10INCH_IN2_DN")
	)
	(segment
		(start 272.697194 1.61925)
		(end 274.055586 1.379728)
		(width 0.14732)
		(layer "In4.Cu")
		(net "DELTA_L_85_10INCH_IN2_DN")
	)
	(segment
		(start 274.225766 1.499108)
		(end 275.440648 8.389874)
		(width 0.14732)
		(layer "In4.Cu")
		(net "DELTA_L_85_10INCH_IN2_DN")
	)
	(segment
		(start 271.473168 8.326882)
		(end 271.830038 8.577072)
		(width 0.14732)
		(layer "In4.Cu")
		(net "DELTA_L_85_10INCH_IN2_DN")
	)
	(segment
		(start 291.615114 8.592312)
		(end 293.19728 8.313166)
		(width 0.14732)
		(layer "In4.Cu")
		(net "DELTA_L_85_10INCH_IN2_DN")
	)
	(segment
		(start 300.30166 1.953514)
		(end 300.42104 1.78308)
		(width 0.14732)
		(layer "In4.Cu")
		(net "DELTA_L_85_10INCH_IN2_DN")
	)
	(segment
		(start 322.692014 5.600954)
		(end 327.439274 5.600954)
		(width 0.14732)
		(layer "In4.Cu")
		(net "DELTA_L_85_10INCH_IN2_DN")
	)
	(segment
		(start 316.111382 1.860042)
		(end 316.230508 1.689862)
		(width 0.14732)
		(layer "In4.Cu")
		(net "DELTA_L_85_10INCH_IN2_DN")
	)
	(segment
		(start 270.26235 1.460754)
		(end 271.473168 8.326882)
		(width 0.14732)
		(layer "In4.Cu")
		(net "DELTA_L_85_10INCH_IN2_DN")
	)
	(segment
		(start 291.258498 8.342122)
		(end 291.615114 8.592312)
		(width 0.14732)
		(layer "In4.Cu")
		(net "DELTA_L_85_10INCH_IN2_DN")
	)
	(segment
		(start 320.176144 1.62814)
		(end 321.534282 1.388364)
		(width 0.14732)
		(layer "In4.Cu")
		(net "DELTA_L_85_10INCH_IN2_DN")
	)
	(segment
		(start 281.968194 1.377442)
		(end 282.138374 1.496822)
		(width 0.14732)
		(layer "In4.Cu")
		(net "DELTA_L_85_10INCH_IN2_DN")
	)
	(segment
		(start 292.374828 1.87325)
		(end 292.494208 1.702816)
		(width 0.14732)
		(layer "In4.Cu")
		(net "DELTA_L_85_10INCH_IN2_DN")
	)
	(segment
		(start 277.629874 8.003794)
		(end 276.54758 1.864868)
		(width 0.14732)
		(layer "In4.Cu")
		(net "DELTA_L_85_10INCH_IN2_DN")
	)
	(segment
		(start 275.797772 8.639556)
		(end 277.379684 8.36041)
		(width 0.14732)
		(layer "In4.Cu")
		(net "DELTA_L_85_10INCH_IN2_DN")
	)
	(segment
		(start 281.565858 7.886446)
		(end 280.490422 1.787398)
		(width 0.14732)
		(layer "In4.Cu")
		(net "DELTA_L_85_10INCH_IN2_DN")
	)
	(segment
		(start 317.187072 7.961376)
		(end 316.111382 1.860042)
		(width 0.14732)
		(layer "In4.Cu")
		(net "DELTA_L_85_10INCH_IN2_DN")
	)
	(segment
		(start 312.979562 8.311896)
		(end 313.229498 7.955788)
		(width 0.14732)
		(layer "In4.Cu")
		(net "DELTA_L_85_10INCH_IN2_DN")
	)
	(segment
		(start 267.059918 5.734304)
		(end 267.508482 8.279638)
		(width 0.14732)
		(layer "In4.Cu")
		(net "DELTA_L_85_10INCH_IN2_DN")
	)
	(segment
		(start 287.648396 8.5344)
		(end 289.230562 8.255254)
		(width 0.14732)
		(layer "In4.Cu")
		(net "DELTA_L_85_10INCH_IN2_DN")
	)
	(segment
		(start 297.821604 1.533906)
		(end 297.991784 1.653286)
		(width 0.14732)
		(layer "In4.Cu")
		(net "DELTA_L_85_10INCH_IN2_DN")
	)
	(segment
		(start 320.885566 8.272018)
		(end 321.135248 7.914894)
		(width 0.14732)
		(layer "In4.Cu")
		(net "DELTA_L_85_10INCH_IN2_DN")
	)
	(segment
		(start 294.02278 1.582674)
		(end 295.201848 8.269224)
		(width 0.14732)
		(layer "In4.Cu")
		(net "DELTA_L_85_10INCH_IN2_DN")
	)
	(segment
		(start 317.759842 1.56972)
		(end 318.946784 8.30072)
		(width 0.14732)
		(layer "In4.Cu")
		(net "DELTA_L_85_10INCH_IN2_DN")
	)
	(segment
		(start 321.534282 1.388364)
		(end 321.705224 1.507998)
		(width 0.14732)
		(layer "In4.Cu")
		(net "DELTA_L_85_10INCH_IN2_DN")
	)
	(segment
		(start 303.128934 8.34644)
		(end 303.485042 8.596376)
		(width 0.14732)
		(layer "In4.Cu")
		(net "DELTA_L_85_10INCH_IN2_DN")
	)
	(segment
		(start 276.66696 1.694688)
		(end 278.025352 1.454912)
		(width 0.14732)
		(layer "In4.Cu")
		(net "DELTA_L_85_10INCH_IN2_DN")
	)
	(segment
		(start 328.414888 0.133858)
		(end 327.733914 -0.048006)
		(width 0.13208)
		(layer "F.Cu")
		(net "DELTA_L_85_10INCH_IN1_DP")
	)
	(segment
		(start 261.557008 0.133858)
		(end 262.237982 -0.048006)
		(width 0.13208)
		(layer "F.Cu")
		(net "DELTA_L_85_10INCH_IN1_DP")
	)
	(segment
		(start 281.27579 2.74193)
		(end 280.200354 -3.356864)
		(width 0.14732)
		(layer "In2.Cu")
		(net "DELTA_L_85_10INCH_IN1_DP")
	)
	(segment
		(start 289.190684 2.754122)
		(end 288.126678 -3.280664)
		(width 0.14732)
		(layer "In2.Cu")
		(net "DELTA_L_85_10INCH_IN1_DP")
	)
	(segment
		(start 272.287746 -3.354832)
		(end 272.537428 -3.711448)
		(width 0.14732)
		(layer "In2.Cu")
		(net "DELTA_L_85_10INCH_IN1_DP")
	)
	(segment
		(start 315.821314 -3.28422)
		(end 316.070996 -3.640582)
		(width 0.14732)
		(layer "In2.Cu")
		(net "DELTA_L_85_10INCH_IN1_DP")
	)
	(segment
		(start 302.200818 -3.576828)
		(end 303.379378 3.106928)
		(width 0.14732)
		(layer "In2.Cu")
		(net "DELTA_L_85_10INCH_IN1_DP")
	)
	(segment
		(start 285.99257 -3.971798)
		(end 286.349186 -3.721862)
		(width 0.14732)
		(layer "In2.Cu")
		(net "DELTA_L_85_10INCH_IN1_DP")
	)
	(segment
		(start 292.334442 -3.627882)
		(end 293.916862 -3.906774)
		(width 0.14732)
		(layer "In2.Cu")
		(net "DELTA_L_85_10INCH_IN1_DP")
	)
	(segment
		(start 319.766696 -3.346196)
		(end 320.016378 -3.702558)
		(width 0.14732)
		(layer "In2.Cu")
		(net "DELTA_L_85_10INCH_IN1_DP")
	)
	(segment
		(start 269.40764 2.749804)
		(end 268.32433 -3.393186)
		(width 0.14732)
		(layer "In2.Cu")
		(net "DELTA_L_85_10INCH_IN1_DP")
	)
	(segment
		(start 299.432472 3.162808)
		(end 299.602906 3.282188)
		(width 0.14732)
		(layer "In2.Cu")
		(net "DELTA_L_85_10INCH_IN1_DP")
	)
	(segment
		(start 297.885866 -3.836162)
		(end 298.242482 -3.58648)
		(width 0.14732)
		(layer "In2.Cu")
		(net "DELTA_L_85_10INCH_IN1_DP")
	)
	(segment
		(start 271.723866 3.08737)
		(end 271.894554 3.207004)
		(width 0.14732)
		(layer "In2.Cu")
		(net "DELTA_L_85_10INCH_IN1_DP")
	)
	(segment
		(start 308.166516 -3.592322)
		(end 309.74919 -3.871468)
		(width 0.14732)
		(layer "In2.Cu")
		(net "DELTA_L_85_10INCH_IN1_DP")
	)
	(segment
		(start 289.95878 -3.916172)
		(end 290.315396 -3.66649)
		(width 0.14732)
		(layer "In2.Cu")
		(net "DELTA_L_85_10INCH_IN1_DP")
	)
	(segment
		(start 313.708034 -3.856228)
		(end 314.065158 -3.606546)
		(width 0.14732)
		(layer "In2.Cu")
		(net "DELTA_L_85_10INCH_IN1_DP")
	)
	(segment
		(start 312.93943 2.811272)
		(end 311.875932 -3.220466)
		(width 0.14732)
		(layer "In2.Cu")
		(net "DELTA_L_85_10INCH_IN1_DP")
	)
	(segment
		(start 296.981372 2.909316)
		(end 297.101006 2.738628)
		(width 0.14732)
		(layer "In2.Cu")
		(net "DELTA_L_85_10INCH_IN1_DP")
	)
	(segment
		(start 293.037768 2.982722)
		(end 293.157402 2.812034)
		(width 0.14732)
		(layer "In2.Cu")
		(net "DELTA_L_85_10INCH_IN1_DP")
	)
	(segment
		(start 312.125614 -3.577082)
		(end 313.708034 -3.856228)
		(width 0.14732)
		(layer "In2.Cu")
		(net "DELTA_L_85_10INCH_IN1_DP")
	)
	(segment
		(start 287.542224 3.044698)
		(end 287.712912 3.164332)
		(width 0.14732)
		(layer "In2.Cu")
		(net "DELTA_L_85_10INCH_IN1_DP")
	)
	(segment
		(start 268.574012 -3.749802)
		(end 270.156432 -4.028694)
		(width 0.14732)
		(layer "In2.Cu")
		(net "DELTA_L_85_10INCH_IN1_DP")
	)
	(segment
		(start 269.288006 2.920238)
		(end 269.40764 2.749804)
		(width 0.14732)
		(layer "In2.Cu")
		(net "DELTA_L_85_10INCH_IN1_DP")
	)
	(segment
		(start 277.220172 3.029966)
		(end 277.339806 2.859278)
		(width 0.14732)
		(layer "In2.Cu")
		(net "DELTA_L_85_10INCH_IN1_DP")
	)
	(segment
		(start 303.962308 -3.223006)
		(end 304.21199 -3.579876)
		(width 0.14732)
		(layer "In2.Cu")
		(net "DELTA_L_85_10INCH_IN1_DP")
	)
	(segment
		(start 306.151534 -3.608324)
		(end 307.337206 3.114294)
		(width 0.14732)
		(layer "In2.Cu")
		(net "DELTA_L_85_10INCH_IN1_DP")
	)
	(segment
		(start 278.44623 -3.665474)
		(end 279.62733 3.03276)
		(width 0.14732)
		(layer "In2.Cu")
		(net "DELTA_L_85_10INCH_IN1_DP")
	)
	(segment
		(start 296.3037 -3.557016)
		(end 297.885866 -3.836162)
		(width 0.14732)
		(layer "In2.Cu")
		(net "DELTA_L_85_10INCH_IN1_DP")
	)
	(segment
		(start 279.62733 3.03276)
		(end 279.798018 3.15214)
		(width 0.14732)
		(layer "In2.Cu")
		(net "DELTA_L_85_10INCH_IN1_DP")
	)
	(segment
		(start 320.84518 2.770632)
		(end 319.766696 -3.346196)
		(width 0.14732)
		(layer "In2.Cu")
		(net "DELTA_L_85_10INCH_IN1_DP")
	)
	(segment
		(start 307.507386 3.233674)
		(end 308.865778 2.994152)
		(width 0.14732)
		(layer "In2.Cu")
		(net "DELTA_L_85_10INCH_IN1_DP")
	)
	(segment
		(start 282.389072 -3.742944)
		(end 283.601414 3.133852)
		(width 0.14732)
		(layer "In2.Cu")
		(net "DELTA_L_85_10INCH_IN1_DP")
	)
	(segment
		(start 320.016378 -3.702558)
		(end 321.598544 -3.981704)
		(width 0.14732)
		(layer "In2.Cu")
		(net "DELTA_L_85_10INCH_IN1_DP")
	)
	(segment
		(start 293.916862 -3.906774)
		(end 294.273478 -3.657092)
		(width 0.14732)
		(layer "In2.Cu")
		(net "DELTA_L_85_10INCH_IN1_DP")
	)
	(segment
		(start 287.712912 3.164332)
		(end 289.07105 2.92481)
		(width 0.14732)
		(layer "In2.Cu")
		(net "DELTA_L_85_10INCH_IN1_DP")
	)
	(segment
		(start 307.337206 3.114294)
		(end 307.507386 3.233674)
		(width 0.14732)
		(layer "In2.Cu")
		(net "DELTA_L_85_10INCH_IN1_DP")
	)
	(segment
		(start 289.07105 2.92481)
		(end 289.190684 2.754122)
		(width 0.14732)
		(layer "In2.Cu")
		(net "DELTA_L_85_10INCH_IN1_DP")
	)
	(segment
		(start 285.250128 2.84353)
		(end 284.160468 -3.336036)
		(width 0.14732)
		(layer "In2.Cu")
		(net "DELTA_L_85_10INCH_IN1_DP")
	)
	(segment
		(start 303.379378 3.106928)
		(end 303.549558 3.226308)
		(width 0.14732)
		(layer "In2.Cu")
		(net "DELTA_L_85_10INCH_IN1_DP")
	)
	(segment
		(start 272.537428 -3.711448)
		(end 274.119848 -3.99034)
		(width 0.14732)
		(layer "In2.Cu")
		(net "DELTA_L_85_10INCH_IN1_DP")
	)
	(segment
		(start 310.105806 -3.621278)
		(end 311.291224 3.101848)
		(width 0.14732)
		(layer "In2.Cu")
		(net "DELTA_L_85_10INCH_IN1_DP")
	)
	(segment
		(start 290.315396 -3.66649)
		(end 291.508942 3.10261)
		(width 0.14732)
		(layer "In2.Cu")
		(net "DELTA_L_85_10INCH_IN1_DP")
	)
	(segment
		(start 275.691346 3.150108)
		(end 275.862034 3.269488)
		(width 0.14732)
		(layer "In2.Cu")
		(net "DELTA_L_85_10INCH_IN1_DP")
	)
	(segment
		(start 273.252692 2.967482)
		(end 273.372326 2.796794)
		(width 0.14732)
		(layer "In2.Cu")
		(net "DELTA_L_85_10INCH_IN1_DP")
	)
	(segment
		(start 296.053764 -3.200146)
		(end 296.3037 -3.557016)
		(width 0.14732)
		(layer "In2.Cu")
		(net "DELTA_L_85_10INCH_IN1_DP")
	)
	(segment
		(start 295.452546 3.029458)
		(end 295.623234 3.148838)
		(width 0.14732)
		(layer "In2.Cu")
		(net "DELTA_L_85_10INCH_IN1_DP")
	)
	(segment
		(start 273.372326 2.796794)
		(end 272.287746 -3.354832)
		(width 0.14732)
		(layer "In2.Cu")
		(net "DELTA_L_85_10INCH_IN1_DP")
	)
	(segment
		(start 278.089614 -3.915156)
		(end 278.44623 -3.665474)
		(width 0.14732)
		(layer "In2.Cu")
		(net "DELTA_L_85_10INCH_IN1_DP")
	)
	(segment
		(start 284.41015 -3.692652)
		(end 285.99257 -3.971798)
		(width 0.14732)
		(layer "In2.Cu")
		(net "DELTA_L_85_10INCH_IN1_DP")
	)
	(segment
		(start 316.777624 2.987802)
		(end 316.897004 2.817114)
		(width 0.14732)
		(layer "In2.Cu")
		(net "DELTA_L_85_10INCH_IN1_DP")
	)
	(segment
		(start 286.349186 -3.721862)
		(end 287.542224 3.044698)
		(width 0.14732)
		(layer "In2.Cu")
		(net "DELTA_L_85_10INCH_IN1_DP")
	)
	(segment
		(start 280.200354 -3.356864)
		(end 280.450036 -3.71348)
		(width 0.14732)
		(layer "In2.Cu")
		(net "DELTA_L_85_10INCH_IN1_DP")
	)
	(segment
		(start 298.242482 -3.58648)
		(end 299.432472 3.162808)
		(width 0.14732)
		(layer "In2.Cu")
		(net "DELTA_L_85_10INCH_IN1_DP")
	)
	(segment
		(start 292.08476 -3.271012)
		(end 292.334442 -3.627882)
		(width 0.14732)
		(layer "In2.Cu")
		(net "DELTA_L_85_10INCH_IN1_DP")
	)
	(segment
		(start 283.601414 3.133852)
		(end 283.772356 3.253232)
		(width 0.14732)
		(layer "In2.Cu")
		(net "DELTA_L_85_10INCH_IN1_DP")
	)
	(segment
		(start 301.080678 2.872232)
		(end 300.011592 -3.190748)
		(width 0.14732)
		(layer "In2.Cu")
		(net "DELTA_L_85_10INCH_IN1_DP")
	)
	(segment
		(start 268.32433 -3.393186)
		(end 268.574012 -3.749802)
		(width 0.14732)
		(layer "In2.Cu")
		(net "DELTA_L_85_10INCH_IN1_DP")
	)
	(segment
		(start 276.507194 -3.63601)
		(end 278.089614 -3.915156)
		(width 0.14732)
		(layer "In2.Cu")
		(net "DELTA_L_85_10INCH_IN1_DP")
	)
	(segment
		(start 320.7258 2.94132)
		(end 320.84518 2.770632)
		(width 0.14732)
		(layer "In2.Cu")
		(net "DELTA_L_85_10INCH_IN1_DP")
	)
	(segment
		(start 304.90795 2.986786)
		(end 305.02733 2.816606)
		(width 0.14732)
		(layer "In2.Cu")
		(net "DELTA_L_85_10INCH_IN1_DP")
	)
	(segment
		(start 304.21199 -3.579876)
		(end 305.794664 -3.858768)
		(width 0.14732)
		(layer "In2.Cu")
		(net "DELTA_L_85_10INCH_IN1_DP")
	)
	(segment
		(start 319.367408 3.180588)
		(end 320.7258 2.94132)
		(width 0.14732)
		(layer "In2.Cu")
		(net "DELTA_L_85_10INCH_IN1_DP")
	)
	(segment
		(start 276.257512 -3.279394)
		(end 276.507194 -3.63601)
		(width 0.14732)
		(layer "In2.Cu")
		(net "DELTA_L_85_10INCH_IN1_DP")
	)
	(segment
		(start 288.37636 -3.63728)
		(end 289.95878 -3.916172)
		(width 0.14732)
		(layer "In2.Cu")
		(net "DELTA_L_85_10INCH_IN1_DP")
	)
	(segment
		(start 291.508942 3.10261)
		(end 291.67963 3.222244)
		(width 0.14732)
		(layer "In2.Cu")
		(net "DELTA_L_85_10INCH_IN1_DP")
	)
	(segment
		(start 281.156156 2.912618)
		(end 281.27579 2.74193)
		(width 0.14732)
		(layer "In2.Cu")
		(net "DELTA_L_85_10INCH_IN1_DP")
	)
	(segment
		(start 285.130494 3.013964)
		(end 285.250128 2.84353)
		(width 0.14732)
		(layer "In2.Cu")
		(net "DELTA_L_85_10INCH_IN1_DP")
	)
	(segment
		(start 322.79209 0.246634)
		(end 327.439274 0.246634)
		(width 0.14732)
		(layer "In2.Cu")
		(net "DELTA_L_85_10INCH_IN1_DP")
	)
	(segment
		(start 305.794664 -3.858768)
		(end 306.151534 -3.608324)
		(width 0.14732)
		(layer "In2.Cu")
		(net "DELTA_L_85_10INCH_IN1_DP")
	)
	(segment
		(start 318.010286 -3.669792)
		(end 319.197228 3.061208)
		(width 0.14732)
		(layer "In2.Cu")
		(net "DELTA_L_85_10INCH_IN1_DP")
	)
	(segment
		(start 267.00099 0.246634)
		(end 267.312902 0.508254)
		(width 0.14732)
		(layer "In2.Cu")
		(net "DELTA_L_85_10INCH_IN1_DP")
	)
	(segment
		(start 294.273478 -3.657092)
		(end 295.452546 3.029458)
		(width 0.14732)
		(layer "In2.Cu")
		(net "DELTA_L_85_10INCH_IN1_DP")
	)
	(segment
		(start 305.02733 2.816606)
		(end 303.962308 -3.223006)
		(width 0.14732)
		(layer "In2.Cu")
		(net "DELTA_L_85_10INCH_IN1_DP")
	)
	(segment
		(start 291.67963 3.222244)
		(end 293.037768 2.982722)
		(width 0.14732)
		(layer "In2.Cu")
		(net "DELTA_L_85_10INCH_IN1_DP")
	)
	(segment
		(start 315.249052 3.10769)
		(end 315.419232 3.22707)
		(width 0.14732)
		(layer "In2.Cu")
		(net "DELTA_L_85_10INCH_IN1_DP")
	)
	(segment
		(start 288.126678 -3.280664)
		(end 288.37636 -3.63728)
		(width 0.14732)
		(layer "In2.Cu")
		(net "DELTA_L_85_10INCH_IN1_DP")
	)
	(segment
		(start 316.897004 2.817114)
		(end 315.821314 -3.28422)
		(width 0.14732)
		(layer "In2.Cu")
		(net "DELTA_L_85_10INCH_IN1_DP")
	)
	(segment
		(start 311.461658 3.221228)
		(end 312.82005 2.981452)
		(width 0.14732)
		(layer "In2.Cu")
		(net "DELTA_L_85_10INCH_IN1_DP")
	)
	(segment
		(start 277.339806 2.859278)
		(end 276.257512 -3.279394)
		(width 0.14732)
		(layer "In2.Cu")
		(net "DELTA_L_85_10INCH_IN1_DP")
	)
	(segment
		(start 295.623234 3.148838)
		(end 296.981372 2.909316)
		(width 0.14732)
		(layer "In2.Cu")
		(net "DELTA_L_85_10INCH_IN1_DP")
	)
	(segment
		(start 262.532622 0.246634)
		(end 267.00099 0.246634)
		(width 0.14732)
		(layer "In2.Cu")
		(net "DELTA_L_85_10INCH_IN1_DP")
	)
	(segment
		(start 311.875932 -3.220466)
		(end 312.125614 -3.577082)
		(width 0.14732)
		(layer "In2.Cu")
		(net "DELTA_L_85_10INCH_IN1_DP")
	)
	(segment
		(start 284.160468 -3.336036)
		(end 284.41015 -3.692652)
		(width 0.14732)
		(layer "In2.Cu")
		(net "DELTA_L_85_10INCH_IN1_DP")
	)
	(segment
		(start 314.065158 -3.606546)
		(end 315.249052 3.10769)
		(width 0.14732)
		(layer "In2.Cu")
		(net "DELTA_L_85_10INCH_IN1_DP")
	)
	(segment
		(start 270.156432 -4.028694)
		(end 270.513048 -3.779012)
		(width 0.14732)
		(layer "In2.Cu")
		(net "DELTA_L_85_10INCH_IN1_DP")
	)
	(segment
		(start 262.237982 -0.048006)
		(end 262.532622 0.246634)
		(width 0.14732)
		(layer "In2.Cu")
		(net "DELTA_L_85_10INCH_IN1_DP")
	)
	(segment
		(start 307.916834 -3.235198)
		(end 308.166516 -3.592322)
		(width 0.14732)
		(layer "In2.Cu")
		(net "DELTA_L_85_10INCH_IN1_DP")
	)
	(segment
		(start 308.865778 2.994152)
		(end 308.985158 2.823972)
		(width 0.14732)
		(layer "In2.Cu")
		(net "DELTA_L_85_10INCH_IN1_DP")
	)
	(segment
		(start 267.75918 3.040126)
		(end 267.929868 3.15976)
		(width 0.14732)
		(layer "In2.Cu")
		(net "DELTA_L_85_10INCH_IN1_DP")
	)
	(segment
		(start 279.798018 3.15214)
		(end 281.156156 2.912618)
		(width 0.14732)
		(layer "In2.Cu")
		(net "DELTA_L_85_10INCH_IN1_DP")
	)
	(segment
		(start 322.63334 0.113284)
		(end 322.79209 0.246634)
		(width 0.14732)
		(layer "In2.Cu")
		(net "DELTA_L_85_10INCH_IN1_DP")
	)
	(segment
		(start 299.602906 3.282188)
		(end 300.961298 3.04292)
		(width 0.14732)
		(layer "In2.Cu")
		(net "DELTA_L_85_10INCH_IN1_DP")
	)
	(segment
		(start 311.291224 3.101848)
		(end 311.461658 3.221228)
		(width 0.14732)
		(layer "In2.Cu")
		(net "DELTA_L_85_10INCH_IN1_DP")
	)
	(segment
		(start 293.157402 2.812034)
		(end 292.08476 -3.271012)
		(width 0.14732)
		(layer "In2.Cu")
		(net "DELTA_L_85_10INCH_IN1_DP")
	)
	(segment
		(start 301.843694 -3.82651)
		(end 302.200818 -3.576828)
		(width 0.14732)
		(layer "In2.Cu")
		(net "DELTA_L_85_10INCH_IN1_DP")
	)
	(segment
		(start 300.261528 -3.547364)
		(end 301.843694 -3.82651)
		(width 0.14732)
		(layer "In2.Cu")
		(net "DELTA_L_85_10INCH_IN1_DP")
	)
	(segment
		(start 271.894554 3.207004)
		(end 273.252692 2.967482)
		(width 0.14732)
		(layer "In2.Cu")
		(net "DELTA_L_85_10INCH_IN1_DP")
	)
	(segment
		(start 303.549558 3.226308)
		(end 304.90795 2.986786)
		(width 0.14732)
		(layer "In2.Cu")
		(net "DELTA_L_85_10INCH_IN1_DP")
	)
	(segment
		(start 274.476464 -3.740658)
		(end 275.691346 3.150108)
		(width 0.14732)
		(layer "In2.Cu")
		(net "DELTA_L_85_10INCH_IN1_DP")
	)
	(segment
		(start 327.439274 0.246634)
		(end 327.733914 -0.048006)
		(width 0.14732)
		(layer "In2.Cu")
		(net "DELTA_L_85_10INCH_IN1_DP")
	)
	(segment
		(start 300.961298 3.04292)
		(end 301.080678 2.872232)
		(width 0.14732)
		(layer "In2.Cu")
		(net "DELTA_L_85_10INCH_IN1_DP")
	)
	(segment
		(start 315.419232 3.22707)
		(end 316.777624 2.987802)
		(width 0.14732)
		(layer "In2.Cu")
		(net "DELTA_L_85_10INCH_IN1_DP")
	)
	(segment
		(start 312.82005 2.981452)
		(end 312.93943 2.811272)
		(width 0.14732)
		(layer "In2.Cu")
		(net "DELTA_L_85_10INCH_IN1_DP")
	)
	(segment
		(start 267.929868 3.15976)
		(end 269.288006 2.920238)
		(width 0.14732)
		(layer "In2.Cu")
		(net "DELTA_L_85_10INCH_IN1_DP")
	)
	(segment
		(start 274.119848 -3.99034)
		(end 274.476464 -3.740658)
		(width 0.14732)
		(layer "In2.Cu")
		(net "DELTA_L_85_10INCH_IN1_DP")
	)
	(segment
		(start 280.450036 -3.71348)
		(end 282.032456 -3.992626)
		(width 0.14732)
		(layer "In2.Cu")
		(net "DELTA_L_85_10INCH_IN1_DP")
	)
	(segment
		(start 321.598544 -3.981704)
		(end 321.955922 -3.731768)
		(width 0.14732)
		(layer "In2.Cu")
		(net "DELTA_L_85_10INCH_IN1_DP")
	)
	(segment
		(start 300.011592 -3.190748)
		(end 300.261528 -3.547364)
		(width 0.14732)
		(layer "In2.Cu")
		(net "DELTA_L_85_10INCH_IN1_DP")
	)
	(segment
		(start 317.653416 -3.919728)
		(end 318.010286 -3.669792)
		(width 0.14732)
		(layer "In2.Cu")
		(net "DELTA_L_85_10INCH_IN1_DP")
	)
	(segment
		(start 282.032456 -3.992626)
		(end 282.389072 -3.742944)
		(width 0.14732)
		(layer "In2.Cu")
		(net "DELTA_L_85_10INCH_IN1_DP")
	)
	(segment
		(start 319.197228 3.061208)
		(end 319.367408 3.180588)
		(width 0.14732)
		(layer "In2.Cu")
		(net "DELTA_L_85_10INCH_IN1_DP")
	)
	(segment
		(start 309.74919 -3.871468)
		(end 310.105806 -3.621278)
		(width 0.14732)
		(layer "In2.Cu")
		(net "DELTA_L_85_10INCH_IN1_DP")
	)
	(segment
		(start 316.070996 -3.640582)
		(end 317.653416 -3.919728)
		(width 0.14732)
		(layer "In2.Cu")
		(net "DELTA_L_85_10INCH_IN1_DP")
	)
	(segment
		(start 270.513048 -3.779012)
		(end 271.723866 3.08737)
		(width 0.14732)
		(layer "In2.Cu")
		(net "DELTA_L_85_10INCH_IN1_DP")
	)
	(segment
		(start 283.772356 3.253232)
		(end 285.130494 3.013964)
		(width 0.14732)
		(layer "In2.Cu")
		(net "DELTA_L_85_10INCH_IN1_DP")
	)
	(segment
		(start 308.985158 2.823972)
		(end 307.916834 -3.235198)
		(width 0.14732)
		(layer "In2.Cu")
		(net "DELTA_L_85_10INCH_IN1_DP")
	)
	(segment
		(start 275.862034 3.269488)
		(end 277.220172 3.029966)
		(width 0.14732)
		(layer "In2.Cu")
		(net "DELTA_L_85_10INCH_IN1_DP")
	)
	(segment
		(start 297.101006 2.738628)
		(end 296.053764 -3.200146)
		(width 0.14732)
		(layer "In2.Cu")
		(net "DELTA_L_85_10INCH_IN1_DP")
	)
	(segment
		(start 267.312902 0.508254)
		(end 267.75918 3.040126)
		(width 0.14732)
		(layer "In2.Cu")
		(net "DELTA_L_85_10INCH_IN1_DP")
	)
	(segment
		(start 321.955922 -3.731768)
		(end 322.63334 0.113284)
		(width 0.14732)
		(layer "In2.Cu")
		(net "DELTA_L_85_10INCH_IN1_DP")
	)
	(segment
		(start 261.557008 0.63373)
		(end 262.237982 0.815594)
		(width 0.13208)
		(layer "F.Cu")
		(net "DELTA_L_85_10INCH_IN1_DN")
	)
	(segment
		(start 328.414888 0.63373)
		(end 327.733914 0.815594)
		(width 0.13208)
		(layer "F.Cu")
		(net "DELTA_L_85_10INCH_IN1_DN")
	)
	(segment
		(start 294.02278 -3.497326)
		(end 295.201848 3.189224)
		(width 0.14732)
		(layer "In2.Cu")
		(net "DELTA_L_85_10INCH_IN1_DN")
	)
	(segment
		(start 278.195532 -3.505708)
		(end 279.376632 3.192526)
		(width 0.14732)
		(layer "In2.Cu")
		(net "DELTA_L_85_10INCH_IN1_DN")
	)
	(segment
		(start 297.821604 -3.546094)
		(end 297.991784 -3.426714)
		(width 0.14732)
		(layer "In2.Cu")
		(net "DELTA_L_85_10INCH_IN1_DN")
	)
	(segment
		(start 267.865606 3.449828)
		(end 269.447518 3.170936)
		(width 0.14732)
		(layer "In2.Cu")
		(net "DELTA_L_85_10INCH_IN1_DN")
	)
	(segment
		(start 277.629874 2.923794)
		(end 276.54758 -3.215132)
		(width 0.14732)
		(layer "In2.Cu")
		(net "DELTA_L_85_10INCH_IN1_DN")
	)
	(segment
		(start 267.059918 0.654304)
		(end 267.508482 3.199638)
		(width 0.14732)
		(layer "In2.Cu")
		(net "DELTA_L_85_10INCH_IN1_DN")
	)
	(segment
		(start 288.535872 -3.386836)
		(end 288.535872 -3.386582)
		(width 0.14732)
		(layer "In2.Cu")
		(net "DELTA_L_85_10INCH_IN1_DN")
	)
	(segment
		(start 305.317398 2.881122)
		(end 304.252376 -3.158744)
		(width 0.14732)
		(layer "In2.Cu")
		(net "DELTA_L_85_10INCH_IN1_DN")
	)
	(segment
		(start 292.494208 -3.377184)
		(end 293.8526 -3.616706)
		(width 0.14732)
		(layer "In2.Cu")
		(net "DELTA_L_85_10INCH_IN1_DN")
	)
	(segment
		(start 309.02529 3.24485)
		(end 309.275226 2.888488)
		(width 0.14732)
		(layer "In2.Cu")
		(net "DELTA_L_85_10INCH_IN1_DN")
	)
	(segment
		(start 283.708094 3.5433)
		(end 285.290006 3.264662)
		(width 0.14732)
		(layer "In2.Cu")
		(net "DELTA_L_85_10INCH_IN1_DN")
	)
	(segment
		(start 321.135248 2.834894)
		(end 320.056764 -3.28168)
		(width 0.14732)
		(layer "In2.Cu")
		(net "DELTA_L_85_10INCH_IN1_DN")
	)
	(segment
		(start 320.176144 -3.45186)
		(end 321.534282 -3.691636)
		(width 0.14732)
		(layer "In2.Cu")
		(net "DELTA_L_85_10INCH_IN1_DN")
	)
	(segment
		(start 317.187072 2.881376)
		(end 316.111382 -3.219958)
		(width 0.14732)
		(layer "In2.Cu")
		(net "DELTA_L_85_10INCH_IN1_DN")
	)
	(segment
		(start 313.643772 -3.56616)
		(end 313.814714 -3.44678)
		(width 0.14732)
		(layer "In2.Cu")
		(net "DELTA_L_85_10INCH_IN1_DN")
	)
	(segment
		(start 282.138374 -3.583178)
		(end 283.35097 3.293618)
		(width 0.14732)
		(layer "In2.Cu")
		(net "DELTA_L_85_10INCH_IN1_DN")
	)
	(segment
		(start 274.225766 -3.580892)
		(end 275.440648 3.309874)
		(width 0.14732)
		(layer "In2.Cu")
		(net "DELTA_L_85_10INCH_IN1_DN")
	)
	(segment
		(start 293.8526 -3.616706)
		(end 294.02278 -3.497326)
		(width 0.14732)
		(layer "In2.Cu")
		(net "DELTA_L_85_10INCH_IN1_DN")
	)
	(segment
		(start 297.140884 3.15976)
		(end 297.391074 2.803144)
		(width 0.14732)
		(layer "In2.Cu")
		(net "DELTA_L_85_10INCH_IN1_DN")
	)
	(segment
		(start 315.354716 3.517138)
		(end 316.93739 3.2385)
		(width 0.14732)
		(layer "In2.Cu")
		(net "DELTA_L_85_10INCH_IN1_DN")
	)
	(segment
		(start 322.692014 0.520954)
		(end 327.439274 0.520954)
		(width 0.14732)
		(layer "In2.Cu")
		(net "DELTA_L_85_10INCH_IN1_DN")
	)
	(segment
		(start 317.759842 -3.51028)
		(end 318.946784 3.22072)
		(width 0.14732)
		(layer "In2.Cu")
		(net "DELTA_L_85_10INCH_IN1_DN")
	)
	(segment
		(start 322.380356 0.259334)
		(end 322.692014 0.520954)
		(width 0.14732)
		(layer "In2.Cu")
		(net "DELTA_L_85_10INCH_IN1_DN")
	)
	(segment
		(start 300.42104 -3.29692)
		(end 301.779432 -3.536442)
		(width 0.14732)
		(layer "In2.Cu")
		(net "DELTA_L_85_10INCH_IN1_DN")
	)
	(segment
		(start 276.54758 -3.215132)
		(end 276.66696 -3.385312)
		(width 0.14732)
		(layer "In2.Cu")
		(net "DELTA_L_85_10INCH_IN1_DN")
	)
	(segment
		(start 277.379684 3.28041)
		(end 277.629874 2.923794)
		(width 0.14732)
		(layer "In2.Cu")
		(net "DELTA_L_85_10INCH_IN1_DN")
	)
	(segment
		(start 273.412204 3.217926)
		(end 273.662394 2.86131)
		(width 0.14732)
		(layer "In2.Cu")
		(net "DELTA_L_85_10INCH_IN1_DN")
	)
	(segment
		(start 297.391074 2.803144)
		(end 296.343832 -3.135884)
		(width 0.14732)
		(layer "In2.Cu")
		(net "DELTA_L_85_10INCH_IN1_DN")
	)
	(segment
		(start 307.086762 3.273806)
		(end 307.44287 3.523742)
		(width 0.14732)
		(layer "In2.Cu")
		(net "DELTA_L_85_10INCH_IN1_DN")
	)
	(segment
		(start 321.705224 -3.572002)
		(end 322.380356 0.259334)
		(width 0.14732)
		(layer "In2.Cu")
		(net "DELTA_L_85_10INCH_IN1_DN")
	)
	(segment
		(start 273.662394 2.86131)
		(end 272.577814 -3.29057)
		(width 0.14732)
		(layer "In2.Cu")
		(net "DELTA_L_85_10INCH_IN1_DN")
	)
	(segment
		(start 307.44287 3.523742)
		(end 309.02529 3.24485)
		(width 0.14732)
		(layer "In2.Cu")
		(net "DELTA_L_85_10INCH_IN1_DN")
	)
	(segment
		(start 262.237982 0.815594)
		(end 262.532622 0.520954)
		(width 0.14732)
		(layer "In2.Cu")
		(net "DELTA_L_85_10INCH_IN1_DN")
	)
	(segment
		(start 268.614398 -3.328924)
		(end 268.733778 -3.499104)
		(width 0.14732)
		(layer "In2.Cu")
		(net "DELTA_L_85_10INCH_IN1_DN")
	)
	(segment
		(start 281.565858 2.806446)
		(end 280.490422 -3.292602)
		(width 0.14732)
		(layer "In2.Cu")
		(net "DELTA_L_85_10INCH_IN1_DN")
	)
	(segment
		(start 276.66696 -3.385312)
		(end 278.025352 -3.625088)
		(width 0.14732)
		(layer "In2.Cu")
		(net "DELTA_L_85_10INCH_IN1_DN")
	)
	(segment
		(start 269.447518 3.170936)
		(end 269.697708 2.81432)
		(width 0.14732)
		(layer "In2.Cu")
		(net "DELTA_L_85_10INCH_IN1_DN")
	)
	(segment
		(start 293.19728 3.233166)
		(end 293.44747 2.87655)
		(width 0.14732)
		(layer "In2.Cu")
		(net "DELTA_L_85_10INCH_IN1_DN")
	)
	(segment
		(start 305.730148 -3.5687)
		(end 305.900836 -3.448812)
		(width 0.14732)
		(layer "In2.Cu")
		(net "DELTA_L_85_10INCH_IN1_DN")
	)
	(segment
		(start 314.998608 3.267202)
		(end 315.354716 3.517138)
		(width 0.14732)
		(layer "In2.Cu")
		(net "DELTA_L_85_10INCH_IN1_DN")
	)
	(segment
		(start 320.885566 3.192018)
		(end 321.135248 2.834894)
		(width 0.14732)
		(layer "In2.Cu")
		(net "DELTA_L_85_10INCH_IN1_DN")
	)
	(segment
		(start 268.733778 -3.499104)
		(end 270.09217 -3.738626)
		(width 0.14732)
		(layer "In2.Cu")
		(net "DELTA_L_85_10INCH_IN1_DN")
	)
	(segment
		(start 295.558972 3.438906)
		(end 297.140884 3.15976)
		(width 0.14732)
		(layer "In2.Cu")
		(net "DELTA_L_85_10INCH_IN1_DN")
	)
	(segment
		(start 279.376632 3.192526)
		(end 279.733756 3.442208)
		(width 0.14732)
		(layer "In2.Cu")
		(net "DELTA_L_85_10INCH_IN1_DN")
	)
	(segment
		(start 300.30166 -3.126486)
		(end 300.42104 -3.29692)
		(width 0.14732)
		(layer "In2.Cu")
		(net "DELTA_L_85_10INCH_IN1_DN")
	)
	(segment
		(start 291.615114 3.512312)
		(end 293.19728 3.233166)
		(width 0.14732)
		(layer "In2.Cu")
		(net "DELTA_L_85_10INCH_IN1_DN")
	)
	(segment
		(start 316.111382 -3.219958)
		(end 316.230508 -3.390138)
		(width 0.14732)
		(layer "In2.Cu")
		(net "DELTA_L_85_10INCH_IN1_DN")
	)
	(segment
		(start 312.166 -3.156204)
		(end 312.28538 -3.326384)
		(width 0.14732)
		(layer "In2.Cu")
		(net "DELTA_L_85_10INCH_IN1_DN")
	)
	(segment
		(start 319.302892 3.470656)
		(end 320.885566 3.192018)
		(width 0.14732)
		(layer "In2.Cu")
		(net "DELTA_L_85_10INCH_IN1_DN")
	)
	(segment
		(start 301.370746 2.936494)
		(end 300.30166 -3.126486)
		(width 0.14732)
		(layer "In2.Cu")
		(net "DELTA_L_85_10INCH_IN1_DN")
	)
	(segment
		(start 308.326282 -3.341878)
		(end 309.684674 -3.5814)
		(width 0.14732)
		(layer "In2.Cu")
		(net "DELTA_L_85_10INCH_IN1_DN")
	)
	(segment
		(start 309.684674 -3.5814)
		(end 309.855362 -3.461766)
		(width 0.14732)
		(layer "In2.Cu")
		(net "DELTA_L_85_10INCH_IN1_DN")
	)
	(segment
		(start 287.648396 3.4544)
		(end 289.230562 3.175254)
		(width 0.14732)
		(layer "In2.Cu")
		(net "DELTA_L_85_10INCH_IN1_DN")
	)
	(segment
		(start 301.950374 -3.417062)
		(end 303.128934 3.26644)
		(width 0.14732)
		(layer "In2.Cu")
		(net "DELTA_L_85_10INCH_IN1_DN")
	)
	(segment
		(start 296.463212 -3.306572)
		(end 297.821604 -3.546094)
		(width 0.14732)
		(layer "In2.Cu")
		(net "DELTA_L_85_10INCH_IN1_DN")
	)
	(segment
		(start 272.697194 -3.46075)
		(end 274.055586 -3.700272)
		(width 0.14732)
		(layer "In2.Cu")
		(net "DELTA_L_85_10INCH_IN1_DN")
	)
	(segment
		(start 317.589154 -3.62966)
		(end 317.759842 -3.51028)
		(width 0.14732)
		(layer "In2.Cu")
		(net "DELTA_L_85_10INCH_IN1_DN")
	)
	(segment
		(start 285.290006 3.264662)
		(end 285.540196 2.908046)
		(width 0.14732)
		(layer "In2.Cu")
		(net "DELTA_L_85_10INCH_IN1_DN")
	)
	(segment
		(start 304.371756 -3.329178)
		(end 305.730148 -3.5687)
		(width 0.14732)
		(layer "In2.Cu")
		(net "DELTA_L_85_10INCH_IN1_DN")
	)
	(segment
		(start 290.064698 -3.506724)
		(end 291.258498 3.262122)
		(width 0.14732)
		(layer "In2.Cu")
		(net "DELTA_L_85_10INCH_IN1_DN")
	)
	(segment
		(start 321.534282 -3.691636)
		(end 321.705224 -3.572002)
		(width 0.14732)
		(layer "In2.Cu")
		(net "DELTA_L_85_10INCH_IN1_DN")
	)
	(segment
		(start 266.901168 0.520954)
		(end 267.059918 0.654304)
		(width 0.14732)
		(layer "In2.Cu")
		(net "DELTA_L_85_10INCH_IN1_DN")
	)
	(segment
		(start 288.416746 -3.216402)
		(end 288.535872 -3.386836)
		(width 0.14732)
		(layer "In2.Cu")
		(net "DELTA_L_85_10INCH_IN1_DN")
	)
	(segment
		(start 316.93739 3.2385)
		(end 317.187072 2.881376)
		(width 0.14732)
		(layer "In2.Cu")
		(net "DELTA_L_85_10INCH_IN1_DN")
	)
	(segment
		(start 281.968194 -3.702558)
		(end 282.138374 -3.583178)
		(width 0.14732)
		(layer "In2.Cu")
		(net "DELTA_L_85_10INCH_IN1_DN")
	)
	(segment
		(start 293.44747 2.87655)
		(end 292.374828 -3.20675)
		(width 0.14732)
		(layer "In2.Cu")
		(net "DELTA_L_85_10INCH_IN1_DN")
	)
	(segment
		(start 292.374828 -3.20675)
		(end 292.494208 -3.377184)
		(width 0.14732)
		(layer "In2.Cu")
		(net "DELTA_L_85_10INCH_IN1_DN")
	)
	(segment
		(start 271.473168 3.246882)
		(end 271.830038 3.497072)
		(width 0.14732)
		(layer "In2.Cu")
		(net "DELTA_L_85_10INCH_IN1_DN")
	)
	(segment
		(start 286.098742 -3.56235)
		(end 287.291526 3.20421)
		(width 0.14732)
		(layer "In2.Cu")
		(net "DELTA_L_85_10INCH_IN1_DN")
	)
	(segment
		(start 313.229498 2.875788)
		(end 312.166 -3.156204)
		(width 0.14732)
		(layer "In2.Cu")
		(net "DELTA_L_85_10INCH_IN1_DN")
	)
	(segment
		(start 285.928308 -3.68173)
		(end 286.098742 -3.56235)
		(width 0.14732)
		(layer "In2.Cu")
		(net "DELTA_L_85_10INCH_IN1_DN")
	)
	(segment
		(start 311.397396 3.511296)
		(end 312.979562 3.231896)
		(width 0.14732)
		(layer "In2.Cu")
		(net "DELTA_L_85_10INCH_IN1_DN")
	)
	(segment
		(start 299.182028 3.32232)
		(end 299.538644 3.572256)
		(width 0.14732)
		(layer "In2.Cu")
		(net "DELTA_L_85_10INCH_IN1_DN")
	)
	(segment
		(start 312.28538 -3.326384)
		(end 313.643772 -3.56616)
		(width 0.14732)
		(layer "In2.Cu")
		(net "DELTA_L_85_10INCH_IN1_DN")
	)
	(segment
		(start 267.508482 3.199638)
		(end 267.865606 3.449828)
		(width 0.14732)
		(layer "In2.Cu")
		(net "DELTA_L_85_10INCH_IN1_DN")
	)
	(segment
		(start 304.252376 -3.158744)
		(end 304.371756 -3.329178)
		(width 0.14732)
		(layer "In2.Cu")
		(net "DELTA_L_85_10INCH_IN1_DN")
	)
	(segment
		(start 318.946784 3.22072)
		(end 319.302892 3.470656)
		(width 0.14732)
		(layer "In2.Cu")
		(net "DELTA_L_85_10INCH_IN1_DN")
	)
	(segment
		(start 299.538644 3.572256)
		(end 301.121064 3.293618)
		(width 0.14732)
		(layer "In2.Cu")
		(net "DELTA_L_85_10INCH_IN1_DN")
	)
	(segment
		(start 289.894518 -3.626104)
		(end 290.064698 -3.506724)
		(width 0.14732)
		(layer "In2.Cu")
		(net "DELTA_L_85_10INCH_IN1_DN")
	)
	(segment
		(start 270.09217 -3.738626)
		(end 270.26235 -3.619246)
		(width 0.14732)
		(layer "In2.Cu")
		(net "DELTA_L_85_10INCH_IN1_DN")
	)
	(segment
		(start 285.540196 2.908046)
		(end 284.450536 -3.271774)
		(width 0.14732)
		(layer "In2.Cu")
		(net "DELTA_L_85_10INCH_IN1_DN")
	)
	(segment
		(start 327.439274 0.520954)
		(end 327.733914 0.815594)
		(width 0.14732)
		(layer "In2.Cu")
		(net "DELTA_L_85_10INCH_IN1_DN")
	)
	(segment
		(start 320.056764 -3.28168)
		(end 320.176144 -3.45186)
		(width 0.14732)
		(layer "In2.Cu")
		(net "DELTA_L_85_10INCH_IN1_DN")
	)
	(segment
		(start 278.025352 -3.625088)
		(end 278.195532 -3.505708)
		(width 0.14732)
		(layer "In2.Cu")
		(net "DELTA_L_85_10INCH_IN1_DN")
	)
	(segment
		(start 262.532622 0.520954)
		(end 266.901168 0.520954)
		(width 0.14732)
		(layer "In2.Cu")
		(net "DELTA_L_85_10INCH_IN1_DN")
	)
	(segment
		(start 279.733756 3.442208)
		(end 281.315668 3.163062)
		(width 0.14732)
		(layer "In2.Cu")
		(net "DELTA_L_85_10INCH_IN1_DN")
	)
	(segment
		(start 311.04078 3.26136)
		(end 311.397396 3.511296)
		(width 0.14732)
		(layer "In2.Cu")
		(net "DELTA_L_85_10INCH_IN1_DN")
	)
	(segment
		(start 271.830038 3.497072)
		(end 273.412204 3.217926)
		(width 0.14732)
		(layer "In2.Cu")
		(net "DELTA_L_85_10INCH_IN1_DN")
	)
	(segment
		(start 280.490422 -3.292602)
		(end 280.609802 -3.462782)
		(width 0.14732)
		(layer "In2.Cu")
		(net "DELTA_L_85_10INCH_IN1_DN")
	)
	(segment
		(start 275.797772 3.559556)
		(end 277.379684 3.28041)
		(width 0.14732)
		(layer "In2.Cu")
		(net "DELTA_L_85_10INCH_IN1_DN")
	)
	(segment
		(start 281.315668 3.163062)
		(end 281.565858 2.806446)
		(width 0.14732)
		(layer "In2.Cu")
		(net "DELTA_L_85_10INCH_IN1_DN")
	)
	(segment
		(start 301.121064 3.293618)
		(end 301.370746 2.936494)
		(width 0.14732)
		(layer "In2.Cu")
		(net "DELTA_L_85_10INCH_IN1_DN")
	)
	(segment
		(start 295.201848 3.189224)
		(end 295.558972 3.438906)
		(width 0.14732)
		(layer "In2.Cu")
		(net "DELTA_L_85_10INCH_IN1_DN")
	)
	(segment
		(start 287.291526 3.20421)
		(end 287.648396 3.4544)
		(width 0.14732)
		(layer "In2.Cu")
		(net "DELTA_L_85_10INCH_IN1_DN")
	)
	(segment
		(start 297.991784 -3.426714)
		(end 299.182028 3.32232)
		(width 0.14732)
		(layer "In2.Cu")
		(net "DELTA_L_85_10INCH_IN1_DN")
	)
	(segment
		(start 274.055586 -3.700272)
		(end 274.225766 -3.580892)
		(width 0.14732)
		(layer "In2.Cu")
		(net "DELTA_L_85_10INCH_IN1_DN")
	)
	(segment
		(start 309.275226 2.888488)
		(end 308.206902 -3.170936)
		(width 0.14732)
		(layer "In2.Cu")
		(net "DELTA_L_85_10INCH_IN1_DN")
	)
	(segment
		(start 303.128934 3.26644)
		(end 303.485042 3.516376)
		(width 0.14732)
		(layer "In2.Cu")
		(net "DELTA_L_85_10INCH_IN1_DN")
	)
	(segment
		(start 283.35097 3.293618)
		(end 283.708094 3.5433)
		(width 0.14732)
		(layer "In2.Cu")
		(net "DELTA_L_85_10INCH_IN1_DN")
	)
	(segment
		(start 301.779432 -3.536442)
		(end 301.950374 -3.417062)
		(width 0.14732)
		(layer "In2.Cu")
		(net "DELTA_L_85_10INCH_IN1_DN")
	)
	(segment
		(start 291.258498 3.262122)
		(end 291.615114 3.512312)
		(width 0.14732)
		(layer "In2.Cu")
		(net "DELTA_L_85_10INCH_IN1_DN")
	)
	(segment
		(start 289.480752 2.818638)
		(end 288.416746 -3.216402)
		(width 0.14732)
		(layer "In2.Cu")
		(net "DELTA_L_85_10INCH_IN1_DN")
	)
	(segment
		(start 296.343832 -3.135884)
		(end 296.463212 -3.306572)
		(width 0.14732)
		(layer "In2.Cu")
		(net "DELTA_L_85_10INCH_IN1_DN")
	)
	(segment
		(start 288.535872 -3.386582)
		(end 289.894518 -3.626104)
		(width 0.14732)
		(layer "In2.Cu")
		(net "DELTA_L_85_10INCH_IN1_DN")
	)
	(segment
		(start 312.979562 3.231896)
		(end 313.229498 2.875788)
		(width 0.14732)
		(layer "In2.Cu")
		(net "DELTA_L_85_10INCH_IN1_DN")
	)
	(segment
		(start 284.450536 -3.271774)
		(end 284.569916 -3.441954)
		(width 0.14732)
		(layer "In2.Cu")
		(net "DELTA_L_85_10INCH_IN1_DN")
	)
	(segment
		(start 316.230508 -3.390138)
		(end 317.589154 -3.62966)
		(width 0.14732)
		(layer "In2.Cu")
		(net "DELTA_L_85_10INCH_IN1_DN")
	)
	(segment
		(start 308.206902 -3.170936)
		(end 308.326282 -3.341878)
		(width 0.14732)
		(layer "In2.Cu")
		(net "DELTA_L_85_10INCH_IN1_DN")
	)
	(segment
		(start 272.577814 -3.29057)
		(end 272.697194 -3.46075)
		(width 0.14732)
		(layer "In2.Cu")
		(net "DELTA_L_85_10INCH_IN1_DN")
	)
	(segment
		(start 275.440648 3.309874)
		(end 275.797772 3.559556)
		(width 0.14732)
		(layer "In2.Cu")
		(net "DELTA_L_85_10INCH_IN1_DN")
	)
	(segment
		(start 269.697708 2.81432)
		(end 268.614398 -3.328924)
		(width 0.14732)
		(layer "In2.Cu")
		(net "DELTA_L_85_10INCH_IN1_DN")
	)
	(segment
		(start 303.485042 3.516376)
		(end 305.067462 3.237484)
		(width 0.14732)
		(layer "In2.Cu")
		(net "DELTA_L_85_10INCH_IN1_DN")
	)
	(segment
		(start 284.569916 -3.441954)
		(end 285.928308 -3.68173)
		(width 0.14732)
		(layer "In2.Cu")
		(net "DELTA_L_85_10INCH_IN1_DN")
	)
	(segment
		(start 270.26235 -3.619246)
		(end 271.473168 3.246882)
		(width 0.14732)
		(layer "In2.Cu")
		(net "DELTA_L_85_10INCH_IN1_DN")
	)
	(segment
		(start 289.230562 3.175254)
		(end 289.480752 2.818638)
		(width 0.14732)
		(layer "In2.Cu")
		(net "DELTA_L_85_10INCH_IN1_DN")
	)
	(segment
		(start 313.814714 -3.44678)
		(end 314.998608 3.267202)
		(width 0.14732)
		(layer "In2.Cu")
		(net "DELTA_L_85_10INCH_IN1_DN")
	)
	(segment
		(start 280.609802 -3.462782)
		(end 281.968194 -3.702558)
		(width 0.14732)
		(layer "In2.Cu")
		(net "DELTA_L_85_10INCH_IN1_DN")
	)
	(segment
		(start 309.855362 -3.461766)
		(end 311.04078 3.26136)
		(width 0.14732)
		(layer "In2.Cu")
		(net "DELTA_L_85_10INCH_IN1_DN")
	)
	(segment
		(start 305.067462 3.237484)
		(end 305.317398 2.881122)
		(width 0.14732)
		(layer "In2.Cu")
		(net "DELTA_L_85_10INCH_IN1_DN")
	)
	(segment
		(start 305.900836 -3.448812)
		(end 307.086762 3.273806)
		(width 0.14732)
		(layer "In2.Cu")
		(net "DELTA_L_85_10INCH_IN1_DN")
	)
	(segment
		(start 306.009802 0.538988)
		(end 307.444394 0.286004)
		(width 0.13208)
		(layer "B.Cu")
		(net "DELTA_L_85_10INCH_BOT_DP")
	)
	(segment
		(start 311.815226 -5.565902)
		(end 312.86704 0.400304)
		(width 0.13208)
		(layer "B.Cu")
		(net "DELTA_L_85_10INCH_BOT_DP")
	)
	(segment
		(start 294.932608 0.380746)
		(end 295.261792 0.61087)
		(width 0.13208)
		(layer "B.Cu")
		(net "DELTA_L_85_10INCH_BOT_DP")
	)
	(segment
		(start 298.842176 0.583946)
		(end 300.276768 0.331216)
		(width 0.13208)
		(layer "B.Cu")
		(net "DELTA_L_85_10INCH_BOT_DP")
	)
	(segment
		(start 261.80542 -2.03835)
		(end 265.49477 -2.03835)
		(width 0.13208)
		(layer "B.Cu")
		(net "DELTA_L_85_10INCH_BOT_DP")
	)
	(segment
		(start 299.664628 -5.506974)
		(end 300.897798 -5.724398)
		(width 0.13208)
		(layer "B.Cu")
		(net "DELTA_L_85_10INCH_BOT_DP")
	)
	(segment
		(start 310.33212 -5.304536)
		(end 310.435244 -5.451602)
		(width 0.13208)
		(layer "B.Cu")
		(net "DELTA_L_85_10INCH_BOT_DP")
	)
	(segment
		(start 285.231078 -5.305044)
		(end 285.334202 -5.45211)
		(width 0.13208)
		(layer "B.Cu")
		(net "DELTA_L_85_10INCH_BOT_DP")
	)
	(segment
		(start 307.675026 -0.042926)
		(end 306.744878 -5.317236)
		(width 0.13208)
		(layer "B.Cu")
		(net "DELTA_L_85_10INCH_BOT_DP")
	)
	(segment
		(start 261.557008 -1.90627)
		(end 261.67334 -1.90627)
		(width 0.13208)
		(layer "B.Cu")
		(net "DELTA_L_85_10INCH_BOT_DP")
	)
	(segment
		(start 297.319446 -5.684774)
		(end 297.466512 -5.58165)
		(width 0.13208)
		(layer "B.Cu")
		(net "DELTA_L_85_10INCH_BOT_DP")
	)
	(segment
		(start 303.270158 -5.451094)
		(end 304.493422 -5.666994)
		(width 0.13208)
		(layer "B.Cu")
		(net "DELTA_L_85_10INCH_BOT_DP")
	)
	(segment
		(start 308.22773 -5.578602)
		(end 309.265066 0.30353)
		(width 0.13208)
		(layer "B.Cu")
		(net "DELTA_L_85_10INCH_BOT_DP")
	)
	(segment
		(start 275.421344 0.05842)
		(end 274.490942 -5.216652)
		(width 0.13208)
		(layer "B.Cu")
		(net "DELTA_L_85_10INCH_BOT_DP")
	)
	(segment
		(start 279.001982 0.032004)
		(end 278.064214 -5.28447)
		(width 0.13208)
		(layer "B.Cu")
		(net "DELTA_L_85_10INCH_BOT_DP")
	)
	(segment
		(start 292.497256 -5.491226)
		(end 293.730172 -5.70865)
		(width 0.13208)
		(layer "B.Cu")
		(net "DELTA_L_85_10INCH_BOT_DP")
	)
	(segment
		(start 315.399674 -5.567934)
		(end 316.43701 0.315722)
		(width 0.13208)
		(layer "B.Cu")
		(net "DELTA_L_85_10INCH_BOT_DP")
	)
	(segment
		(start 293.730172 -5.70865)
		(end 293.877238 -5.605526)
		(width 0.13208)
		(layer "B.Cu")
		(net "DELTA_L_85_10INCH_BOT_DP")
	)
	(segment
		(start 293.877238 -5.605526)
		(end 294.932608 0.380746)
		(width 0.13208)
		(layer "B.Cu")
		(net "DELTA_L_85_10INCH_BOT_DP")
	)
	(segment
		(start 286.170624 0.022098)
		(end 285.231078 -5.305044)
		(width 0.13208)
		(layer "B.Cu")
		(net "DELTA_L_85_10INCH_BOT_DP")
	)
	(segment
		(start 265.882374 -1.713484)
		(end 266.265914 0.463042)
		(width 0.13208)
		(layer "B.Cu")
		(net "DELTA_L_85_10INCH_BOT_DP")
	)
	(segment
		(start 310.435244 -5.451602)
		(end 311.66816 -5.669026)
		(width 0.13208)
		(layer "B.Cu")
		(net "DELTA_L_85_10INCH_BOT_DP")
	)
	(segment
		(start 269.846552 0.436372)
		(end 270.175228 0.666496)
		(width 0.13208)
		(layer "B.Cu")
		(net "DELTA_L_85_10INCH_BOT_DP")
	)
	(segment
		(start 321.183 -5.493512)
		(end 322.41617 -5.710936)
		(width 0.13208)
		(layer "B.Cu")
		(net "DELTA_L_85_10INCH_BOT_DP")
	)
	(segment
		(start 291.691822 0.695452)
		(end 293.126668 0.442722)
		(width 0.13208)
		(layer "B.Cu")
		(net "DELTA_L_85_10INCH_BOT_DP")
	)
	(segment
		(start 285.334202 -5.45211)
		(end 286.567118 -5.669534)
		(width 0.13208)
		(layer "B.Cu")
		(net "DELTA_L_85_10INCH_BOT_DP")
	)
	(segment
		(start 297.466512 -5.58165)
		(end 298.513246 0.353822)
		(width 0.13208)
		(layer "B.Cu")
		(net "DELTA_L_85_10INCH_BOT_DP")
	)
	(segment
		(start 290.298378 -5.571744)
		(end 291.362638 0.465328)
		(width 0.13208)
		(layer "B.Cu")
		(net "DELTA_L_85_10INCH_BOT_DP")
	)
	(segment
		(start 312.86704 0.400304)
		(end 313.196224 0.630428)
		(width 0.13208)
		(layer "B.Cu")
		(net "DELTA_L_85_10INCH_BOT_DP")
	)
	(segment
		(start 268.260068 0.111252)
		(end 267.3096 -5.277358)
		(width 0.13208)
		(layer "B.Cu")
		(net "DELTA_L_85_10INCH_BOT_DP")
	)
	(segment
		(start 275.821394 -5.58546)
		(end 275.973794 -5.478272)
		(width 0.13208)
		(layer "B.Cu")
		(net "DELTA_L_85_10INCH_BOT_DP")
	)
	(segment
		(start 299.561758 -5.359654)
		(end 299.664628 -5.506974)
		(width 0.13208)
		(layer "B.Cu")
		(net "DELTA_L_85_10INCH_BOT_DP")
	)
	(segment
		(start 313.196224 0.630428)
		(end 314.63107 0.377698)
		(width 0.13208)
		(layer "B.Cu")
		(net "DELTA_L_85_10INCH_BOT_DP")
	)
	(segment
		(start 277.007828 0.38354)
		(end 277.336504 0.613664)
		(width 0.13208)
		(layer "B.Cu")
		(net "DELTA_L_85_10INCH_BOT_DP")
	)
	(segment
		(start 318.200786 0.292862)
		(end 318.431164 -0.036068)
		(width 0.13208)
		(layer "B.Cu")
		(net "DELTA_L_85_10INCH_BOT_DP")
	)
	(segment
		(start 293.356538 0.114046)
		(end 292.394132 -5.34416)
		(width 0.13208)
		(layer "B.Cu")
		(net "DELTA_L_85_10INCH_BOT_DP")
	)
	(segment
		(start 306.848002 -5.464302)
		(end 308.080918 -5.681726)
		(width 0.13208)
		(layer "B.Cu")
		(net "DELTA_L_85_10INCH_BOT_DP")
	)
	(segment
		(start 307.444394 0.286004)
		(end 307.675026 -0.042926)
		(width 0.13208)
		(layer "B.Cu")
		(net "DELTA_L_85_10INCH_BOT_DP")
	)
	(segment
		(start 293.126668 0.442722)
		(end 293.356538 0.114046)
		(width 0.13208)
		(layer "B.Cu")
		(net "DELTA_L_85_10INCH_BOT_DP")
	)
	(segment
		(start 271.840706 0.084836)
		(end 270.89989 -5.248656)
		(width 0.13208)
		(layer "B.Cu")
		(net "DELTA_L_85_10INCH_BOT_DP")
	)
	(segment
		(start 304.646076 -5.56006)
		(end 305.680872 0.308356)
		(width 0.13208)
		(layer "B.Cu")
		(net "DELTA_L_85_10INCH_BOT_DP")
	)
	(segment
		(start 268.640052 -5.645912)
		(end 268.792706 -5.538724)
		(width 0.13208)
		(layer "B.Cu")
		(net "DELTA_L_85_10INCH_BOT_DP")
	)
	(segment
		(start 305.680872 0.308356)
		(end 306.009802 0.538988)
		(width 0.13208)
		(layer "B.Cu")
		(net "DELTA_L_85_10INCH_BOT_DP")
	)
	(segment
		(start 261.67334 -1.90627)
		(end 261.80542 -2.03835)
		(width 0.13208)
		(layer "B.Cu")
		(net "DELTA_L_85_10INCH_BOT_DP")
	)
	(segment
		(start 287.760664 0.368554)
		(end 288.08934 0.599186)
		(width 0.13208)
		(layer "B.Cu")
		(net "DELTA_L_85_10INCH_BOT_DP")
	)
	(segment
		(start 306.744878 -5.317236)
		(end 306.848002 -5.464302)
		(width 0.13208)
		(layer "B.Cu")
		(net "DELTA_L_85_10INCH_BOT_DP")
	)
	(segment
		(start 285.939992 0.351028)
		(end 286.170624 0.022098)
		(width 0.13208)
		(layer "B.Cu")
		(net "DELTA_L_85_10INCH_BOT_DP")
	)
	(segment
		(start 322.011294 -0.062992)
		(end 321.079876 -5.346446)
		(width 0.13208)
		(layer "B.Cu")
		(net "DELTA_L_85_10INCH_BOT_DP")
	)
	(segment
		(start 296.926762 0.028956)
		(end 295.983406 -5.320284)
		(width 0.13208)
		(layer "B.Cu")
		(net "DELTA_L_85_10INCH_BOT_DP")
	)
	(segment
		(start 300.897798 -5.724398)
		(end 301.050452 -5.617464)
		(width 0.13208)
		(layer "B.Cu")
		(net "DELTA_L_85_10INCH_BOT_DP")
	)
	(segment
		(start 315.252608 -5.671058)
		(end 315.399674 -5.567934)
		(width 0.13208)
		(layer "B.Cu")
		(net "DELTA_L_85_10INCH_BOT_DP")
	)
	(segment
		(start 323.719698 -2.026666)
		(end 328.183748 -2.026666)
		(width 0.13208)
		(layer "B.Cu")
		(net "DELTA_L_85_10INCH_BOT_DP")
	)
	(segment
		(start 281.754072 -5.451348)
		(end 282.977336 -5.667248)
		(width 0.13208)
		(layer "B.Cu")
		(net "DELTA_L_85_10INCH_BOT_DP")
	)
	(segment
		(start 298.513246 0.353822)
		(end 298.842176 0.583946)
		(width 0.13208)
		(layer "B.Cu")
		(net "DELTA_L_85_10INCH_BOT_DP")
	)
	(segment
		(start 300.506892 0.002032)
		(end 299.561758 -5.359654)
		(width 0.13208)
		(layer "B.Cu")
		(net "DELTA_L_85_10INCH_BOT_DP")
	)
	(segment
		(start 314.86094 0.049022)
		(end 313.916568 -5.306568)
		(width 0.13208)
		(layer "B.Cu")
		(net "DELTA_L_85_10INCH_BOT_DP")
	)
	(segment
		(start 278.171402 -5.437124)
		(end 279.394666 -5.653024)
		(width 0.13208)
		(layer "B.Cu")
		(net "DELTA_L_85_10INCH_BOT_DP")
	)
	(segment
		(start 288.918396 -5.457444)
		(end 290.151312 -5.674868)
		(width 0.13208)
		(layer "B.Cu")
		(net "DELTA_L_85_10INCH_BOT_DP")
	)
	(segment
		(start 280.588466 0.357124)
		(end 280.917142 0.587248)
		(width 0.13208)
		(layer "B.Cu")
		(net "DELTA_L_85_10INCH_BOT_DP")
	)
	(segment
		(start 317.497206 -5.331206)
		(end 317.60033 -5.478272)
		(width 0.13208)
		(layer "B.Cu")
		(net "DELTA_L_85_10INCH_BOT_DP")
	)
	(segment
		(start 295.983406 -5.320284)
		(end 296.08653 -5.46735)
		(width 0.13208)
		(layer "B.Cu")
		(net "DELTA_L_85_10INCH_BOT_DP")
	)
	(segment
		(start 268.792706 -5.538724)
		(end 269.846552 0.436372)
		(width 0.13208)
		(layer "B.Cu")
		(net "DELTA_L_85_10INCH_BOT_DP")
	)
	(segment
		(start 311.258966 -0.048006)
		(end 310.33212 -5.304536)
		(width 0.13208)
		(layer "B.Cu")
		(net "DELTA_L_85_10INCH_BOT_DP")
	)
	(segment
		(start 273.42719 0.409956)
		(end 273.755866 0.64008)
		(width 0.13208)
		(layer "B.Cu")
		(net "DELTA_L_85_10INCH_BOT_DP")
	)
	(segment
		(start 288.08934 0.599186)
		(end 289.52444 0.346202)
		(width 0.13208)
		(layer "B.Cu")
		(net "DELTA_L_85_10INCH_BOT_DP")
	)
	(segment
		(start 295.261792 0.61087)
		(end 296.696384 0.357886)
		(width 0.13208)
		(layer "B.Cu")
		(net "DELTA_L_85_10INCH_BOT_DP")
	)
	(segment
		(start 328.183748 -2.026666)
		(end 328.304144 -1.90627)
		(width 0.13208)
		(layer "B.Cu")
		(net "DELTA_L_85_10INCH_BOT_DP")
	)
	(segment
		(start 314.019692 -5.453634)
		(end 315.252608 -5.671058)
		(width 0.13208)
		(layer "B.Cu")
		(net "DELTA_L_85_10INCH_BOT_DP")
	)
	(segment
		(start 328.304144 -1.90627)
		(end 328.414888 -1.90627)
		(width 0.13208)
		(layer "B.Cu")
		(net "DELTA_L_85_10INCH_BOT_DP")
	)
	(segment
		(start 266.265914 0.463042)
		(end 266.59459 0.692912)
		(width 0.13208)
		(layer "B.Cu")
		(net "DELTA_L_85_10INCH_BOT_DP")
	)
	(segment
		(start 316.43701 0.315722)
		(end 316.766194 0.545846)
		(width 0.13208)
		(layer "B.Cu")
		(net "DELTA_L_85_10INCH_BOT_DP")
	)
	(segment
		(start 268.029182 0.440182)
		(end 268.260068 0.111252)
		(width 0.13208)
		(layer "B.Cu")
		(net "DELTA_L_85_10INCH_BOT_DP")
	)
	(segment
		(start 267.416788 -5.430012)
		(end 268.640052 -5.645912)
		(width 0.13208)
		(layer "B.Cu")
		(net "DELTA_L_85_10INCH_BOT_DP")
	)
	(segment
		(start 267.3096 -5.277358)
		(end 267.416788 -5.430012)
		(width 0.13208)
		(layer "B.Cu")
		(net "DELTA_L_85_10INCH_BOT_DP")
	)
	(segment
		(start 277.336504 0.613664)
		(end 278.771096 0.360934)
		(width 0.13208)
		(layer "B.Cu")
		(net "DELTA_L_85_10INCH_BOT_DP")
	)
	(segment
		(start 283.12999 -5.560314)
		(end 284.17647 0.37338)
		(width 0.13208)
		(layer "B.Cu")
		(net "DELTA_L_85_10INCH_BOT_DP")
	)
	(segment
		(start 279.394666 -5.653024)
		(end 279.54732 -5.545836)
		(width 0.13208)
		(layer "B.Cu")
		(net "DELTA_L_85_10INCH_BOT_DP")
	)
	(segment
		(start 320.346578 0.518922)
		(end 321.78117 0.266192)
		(width 0.13208)
		(layer "B.Cu")
		(net "DELTA_L_85_10INCH_BOT_DP")
	)
	(segment
		(start 275.190458 0.38735)
		(end 275.421344 0.05842)
		(width 0.13208)
		(layer "B.Cu")
		(net "DELTA_L_85_10INCH_BOT_DP")
	)
	(segment
		(start 296.08653 -5.46735)
		(end 297.319446 -5.684774)
		(width 0.13208)
		(layer "B.Cu")
		(net "DELTA_L_85_10INCH_BOT_DP")
	)
	(segment
		(start 322.41617 -5.710936)
		(end 322.563236 -5.607812)
		(width 0.13208)
		(layer "B.Cu")
		(net "DELTA_L_85_10INCH_BOT_DP")
	)
	(segment
		(start 304.493422 -5.666994)
		(end 304.646076 -5.56006)
		(width 0.13208)
		(layer "B.Cu")
		(net "DELTA_L_85_10INCH_BOT_DP")
	)
	(segment
		(start 308.080918 -5.681726)
		(end 308.22773 -5.578602)
		(width 0.13208)
		(layer "B.Cu")
		(net "DELTA_L_85_10INCH_BOT_DP")
	)
	(segment
		(start 304.087022 -0.059436)
		(end 303.16297 -5.29844)
		(width 0.13208)
		(layer "B.Cu")
		(net "DELTA_L_85_10INCH_BOT_DP")
	)
	(segment
		(start 311.66816 -5.669026)
		(end 311.815226 -5.565902)
		(width 0.13208)
		(layer "B.Cu")
		(net "DELTA_L_85_10INCH_BOT_DP")
	)
	(segment
		(start 289.754564 0.017018)
		(end 288.815272 -5.310378)
		(width 0.13208)
		(layer "B.Cu")
		(net "DELTA_L_85_10INCH_BOT_DP")
	)
	(segment
		(start 321.78117 0.266192)
		(end 322.011294 -0.062992)
		(width 0.13208)
		(layer "B.Cu")
		(net "DELTA_L_85_10INCH_BOT_DP")
	)
	(segment
		(start 280.917142 0.587248)
		(end 282.351734 0.334518)
		(width 0.13208)
		(layer "B.Cu")
		(net "DELTA_L_85_10INCH_BOT_DP")
	)
	(segment
		(start 318.431164 -0.036068)
		(end 317.497206 -5.331206)
		(width 0.13208)
		(layer "B.Cu")
		(net "DELTA_L_85_10INCH_BOT_DP")
	)
	(segment
		(start 301.050452 -5.617464)
		(end 302.092868 0.2921)
		(width 0.13208)
		(layer "B.Cu")
		(net "DELTA_L_85_10INCH_BOT_DP")
	)
	(segment
		(start 275.973794 -5.478272)
		(end 277.007828 0.38354)
		(width 0.13208)
		(layer "B.Cu")
		(net "DELTA_L_85_10INCH_BOT_DP")
	)
	(segment
		(start 316.766194 0.545846)
		(end 318.200786 0.292862)
		(width 0.13208)
		(layer "B.Cu")
		(net "DELTA_L_85_10INCH_BOT_DP")
	)
	(segment
		(start 320.017394 0.288798)
		(end 320.346578 0.518922)
		(width 0.13208)
		(layer "B.Cu")
		(net "DELTA_L_85_10INCH_BOT_DP")
	)
	(segment
		(start 311.028842 0.281178)
		(end 311.258966 -0.048006)
		(width 0.13208)
		(layer "B.Cu")
		(net "DELTA_L_85_10INCH_BOT_DP")
	)
	(segment
		(start 282.58262 0.005588)
		(end 281.646884 -5.298948)
		(width 0.13208)
		(layer "B.Cu")
		(net "DELTA_L_85_10INCH_BOT_DP")
	)
	(segment
		(start 321.079876 -5.346446)
		(end 321.183 -5.493512)
		(width 0.13208)
		(layer "B.Cu")
		(net "DELTA_L_85_10INCH_BOT_DP")
	)
	(segment
		(start 323.082158 -2.664206)
		(end 323.719698 -2.026666)
		(width 0.13208)
		(layer "B.Cu")
		(net "DELTA_L_85_10INCH_BOT_DP")
	)
	(segment
		(start 313.916568 -5.306568)
		(end 314.019692 -5.453634)
		(width 0.13208)
		(layer "B.Cu")
		(net "DELTA_L_85_10INCH_BOT_DP")
	)
	(segment
		(start 289.52444 0.346202)
		(end 289.754564 0.017018)
		(width 0.13208)
		(layer "B.Cu")
		(net "DELTA_L_85_10INCH_BOT_DP")
	)
	(segment
		(start 314.63107 0.377698)
		(end 314.86094 0.049022)
		(width 0.13208)
		(layer "B.Cu")
		(net "DELTA_L_85_10INCH_BOT_DP")
	)
	(segment
		(start 303.856136 0.269494)
		(end 304.087022 -0.059436)
		(width 0.13208)
		(layer "B.Cu")
		(net "DELTA_L_85_10INCH_BOT_DP")
	)
	(segment
		(start 291.362638 0.465328)
		(end 291.691822 0.695452)
		(width 0.13208)
		(layer "B.Cu")
		(net "DELTA_L_85_10INCH_BOT_DP")
	)
	(segment
		(start 282.977336 -5.667248)
		(end 283.12999 -5.560314)
		(width 0.13208)
		(layer "B.Cu")
		(net "DELTA_L_85_10INCH_BOT_DP")
	)
	(segment
		(start 270.175228 0.666496)
		(end 271.60982 0.413766)
		(width 0.13208)
		(layer "B.Cu")
		(net "DELTA_L_85_10INCH_BOT_DP")
	)
	(segment
		(start 292.394132 -5.34416)
		(end 292.497256 -5.491226)
		(width 0.13208)
		(layer "B.Cu")
		(net "DELTA_L_85_10INCH_BOT_DP")
	)
	(segment
		(start 274.490942 -5.216652)
		(end 274.59813 -5.36956)
		(width 0.13208)
		(layer "B.Cu")
		(net "DELTA_L_85_10INCH_BOT_DP")
	)
	(segment
		(start 272.382996 -5.510022)
		(end 273.42719 0.409956)
		(width 0.13208)
		(layer "B.Cu")
		(net "DELTA_L_85_10INCH_BOT_DP")
	)
	(segment
		(start 274.59813 -5.36956)
		(end 275.821394 -5.58546)
		(width 0.13208)
		(layer "B.Cu")
		(net "DELTA_L_85_10INCH_BOT_DP")
	)
	(segment
		(start 270.89989 -5.248656)
		(end 271.007078 -5.40131)
		(width 0.13208)
		(layer "B.Cu")
		(net "DELTA_L_85_10INCH_BOT_DP")
	)
	(segment
		(start 309.265066 0.30353)
		(end 309.593996 0.534162)
		(width 0.13208)
		(layer "B.Cu")
		(net "DELTA_L_85_10INCH_BOT_DP")
	)
	(segment
		(start 322.563236 -5.607812)
		(end 323.082158 -2.664206)
		(width 0.13208)
		(layer "B.Cu")
		(net "DELTA_L_85_10INCH_BOT_DP")
	)
	(segment
		(start 302.092868 0.2921)
		(end 302.421544 0.522224)
		(width 0.13208)
		(layer "B.Cu")
		(net "DELTA_L_85_10INCH_BOT_DP")
	)
	(segment
		(start 278.064214 -5.28447)
		(end 278.171402 -5.437124)
		(width 0.13208)
		(layer "B.Cu")
		(net "DELTA_L_85_10INCH_BOT_DP")
	)
	(segment
		(start 282.351734 0.334518)
		(end 282.58262 0.005588)
		(width 0.13208)
		(layer "B.Cu")
		(net "DELTA_L_85_10INCH_BOT_DP")
	)
	(segment
		(start 303.16297 -5.29844)
		(end 303.270158 -5.451094)
		(width 0.13208)
		(layer "B.Cu")
		(net "DELTA_L_85_10INCH_BOT_DP")
	)
	(segment
		(start 290.151312 -5.674868)
		(end 290.298378 -5.571744)
		(width 0.13208)
		(layer "B.Cu")
		(net "DELTA_L_85_10INCH_BOT_DP")
	)
	(segment
		(start 271.60982 0.413766)
		(end 271.840706 0.084836)
		(width 0.13208)
		(layer "B.Cu")
		(net "DELTA_L_85_10INCH_BOT_DP")
	)
	(segment
		(start 286.714184 -5.56641)
		(end 287.760664 0.368554)
		(width 0.13208)
		(layer "B.Cu")
		(net "DELTA_L_85_10INCH_BOT_DP")
	)
	(segment
		(start 278.771096 0.360934)
		(end 279.001982 0.032004)
		(width 0.13208)
		(layer "B.Cu")
		(net "DELTA_L_85_10INCH_BOT_DP")
	)
	(segment
		(start 288.815272 -5.310378)
		(end 288.918396 -5.457444)
		(width 0.13208)
		(layer "B.Cu")
		(net "DELTA_L_85_10INCH_BOT_DP")
	)
	(segment
		(start 281.646884 -5.298948)
		(end 281.754072 -5.451348)
		(width 0.13208)
		(layer "B.Cu")
		(net "DELTA_L_85_10INCH_BOT_DP")
	)
	(segment
		(start 286.567118 -5.669534)
		(end 286.714184 -5.56641)
		(width 0.13208)
		(layer "B.Cu")
		(net "DELTA_L_85_10INCH_BOT_DP")
	)
	(segment
		(start 309.593996 0.534162)
		(end 311.028842 0.281178)
		(width 0.13208)
		(layer "B.Cu")
		(net "DELTA_L_85_10INCH_BOT_DP")
	)
	(segment
		(start 272.230342 -5.61721)
		(end 272.382996 -5.510022)
		(width 0.13208)
		(layer "B.Cu")
		(net "DELTA_L_85_10INCH_BOT_DP")
	)
	(segment
		(start 317.60033 -5.478272)
		(end 318.833246 -5.695696)
		(width 0.13208)
		(layer "B.Cu")
		(net "DELTA_L_85_10INCH_BOT_DP")
	)
	(segment
		(start 318.833246 -5.695696)
		(end 318.980312 -5.592572)
		(width 0.13208)
		(layer "B.Cu")
		(net "DELTA_L_85_10INCH_BOT_DP")
	)
	(segment
		(start 273.755866 0.64008)
		(end 275.190458 0.38735)
		(width 0.13208)
		(layer "B.Cu")
		(net "DELTA_L_85_10INCH_BOT_DP")
	)
	(segment
		(start 284.17647 0.37338)
		(end 284.505146 0.604012)
		(width 0.13208)
		(layer "B.Cu")
		(net "DELTA_L_85_10INCH_BOT_DP")
	)
	(segment
		(start 302.421544 0.522224)
		(end 303.856136 0.269494)
		(width 0.13208)
		(layer "B.Cu")
		(net "DELTA_L_85_10INCH_BOT_DP")
	)
	(segment
		(start 279.54732 -5.545836)
		(end 280.588466 0.357124)
		(width 0.13208)
		(layer "B.Cu")
		(net "DELTA_L_85_10INCH_BOT_DP")
	)
	(segment
		(start 265.49477 -2.03835)
		(end 265.882374 -1.713484)
		(width 0.13208)
		(layer "B.Cu")
		(net "DELTA_L_85_10INCH_BOT_DP")
	)
	(segment
		(start 318.980312 -5.592572)
		(end 320.017394 0.288798)
		(width 0.13208)
		(layer "B.Cu")
		(net "DELTA_L_85_10INCH_BOT_DP")
	)
	(segment
		(start 296.696384 0.357886)
		(end 296.926762 0.028956)
		(width 0.13208)
		(layer "B.Cu")
		(net "DELTA_L_85_10INCH_BOT_DP")
	)
	(segment
		(start 271.007078 -5.40131)
		(end 272.230342 -5.61721)
		(width 0.13208)
		(layer "B.Cu")
		(net "DELTA_L_85_10INCH_BOT_DP")
	)
	(segment
		(start 300.276768 0.331216)
		(end 300.506892 0.002032)
		(width 0.13208)
		(layer "B.Cu")
		(net "DELTA_L_85_10INCH_BOT_DP")
	)
	(segment
		(start 266.59459 0.692912)
		(end 268.029182 0.440182)
		(width 0.13208)
		(layer "B.Cu")
		(net "DELTA_L_85_10INCH_BOT_DP")
	)
	(segment
		(start 284.505146 0.604012)
		(end 285.939992 0.351028)
		(width 0.13208)
		(layer "B.Cu")
		(net "DELTA_L_85_10INCH_BOT_DP")
	)
	(segment
		(start 275.147278 -0.00254)
		(end 274.216876 -5.277358)
		(width 0.13208)
		(layer "B.Cu")
		(net "DELTA_L_85_10INCH_BOT_DN")
	)
	(segment
		(start 297.70324 -5.732272)
		(end 298.749974 0.202946)
		(width 0.13208)
		(layer "B.Cu")
		(net "DELTA_L_85_10INCH_BOT_DN")
	)
	(segment
		(start 289.480752 -0.043688)
		(end 288.541206 -5.371338)
		(width 0.13208)
		(layer "B.Cu")
		(net "DELTA_L_85_10INCH_BOT_DN")
	)
	(segment
		(start 316.8269 0.272034)
		(end 318.04991 0.056134)
		(width 0.13208)
		(layer "B.Cu")
		(net "DELTA_L_85_10INCH_BOT_DN")
	)
	(segment
		(start 291.599366 0.314452)
		(end 291.752528 0.42164)
		(width 0.13208)
		(layer "B.Cu")
		(net "DELTA_L_85_10INCH_BOT_DN")
	)
	(segment
		(start 267.035534 -5.338318)
		(end 267.266166 -5.66674)
		(width 0.13208)
		(layer "B.Cu")
		(net "DELTA_L_85_10INCH_BOT_DN")
	)
	(segment
		(start 265.589258 -2.29743)
		(end 266.121134 -1.851406)
		(width 0.13208)
		(layer "B.Cu")
		(net "DELTA_L_85_10INCH_BOT_DN")
	)
	(segment
		(start 281.60345 -5.688076)
		(end 283.038042 -5.94106)
		(width 0.13208)
		(layer "B.Cu")
		(net "DELTA_L_85_10INCH_BOT_DN")
	)
	(segment
		(start 322.47713 -5.985002)
		(end 322.799964 -5.758434)
		(width 0.13208)
		(layer "B.Cu")
		(net "DELTA_L_85_10INCH_BOT_DN")
	)
	(segment
		(start 290.212272 -5.948934)
		(end 290.535106 -5.722366)
		(width 0.13208)
		(layer "B.Cu")
		(net "DELTA_L_85_10INCH_BOT_DN")
	)
	(segment
		(start 284.566106 0.329946)
		(end 285.78937 0.1143)
		(width 0.13208)
		(layer "B.Cu")
		(net "DELTA_L_85_10INCH_BOT_DN")
	)
	(segment
		(start 295.322498 0.337058)
		(end 295.322498 0.336804)
		(width 0.13208)
		(layer "B.Cu")
		(net "DELTA_L_85_10INCH_BOT_DN")
	)
	(segment
		(start 270.625824 -5.309616)
		(end 270.856456 -5.638038)
		(width 0.13208)
		(layer "B.Cu")
		(net "DELTA_L_85_10INCH_BOT_DN")
	)
	(segment
		(start 281.372818 -5.359908)
		(end 281.60345 -5.688076)
		(width 0.13208)
		(layer "B.Cu")
		(net "DELTA_L_85_10INCH_BOT_DN")
	)
	(segment
		(start 295.935908 -5.704078)
		(end 297.380406 -5.95884)
		(width 0.13208)
		(layer "B.Cu")
		(net "DELTA_L_85_10INCH_BOT_DN")
	)
	(segment
		(start 261.557008 -2.406142)
		(end 261.667752 -2.406142)
		(width 0.13208)
		(layer "B.Cu")
		(net "DELTA_L_85_10INCH_BOT_DN")
	)
	(segment
		(start 320.254122 0.137922)
		(end 320.407284 0.24511)
		(width 0.13208)
		(layer "B.Cu")
		(net "DELTA_L_85_10INCH_BOT_DN")
	)
	(segment
		(start 310.985154 -0.108712)
		(end 310.058308 -5.365242)
		(width 0.13208)
		(layer "B.Cu")
		(net "DELTA_L_85_10INCH_BOT_DN")
	)
	(segment
		(start 320.80581 -5.407406)
		(end 321.032378 -5.73024)
		(width 0.13208)
		(layer "B.Cu")
		(net "DELTA_L_85_10INCH_BOT_DN")
	)
	(segment
		(start 279.784048 -5.696458)
		(end 280.825194 0.206248)
		(width 0.13208)
		(layer "B.Cu")
		(net "DELTA_L_85_10INCH_BOT_DN")
	)
	(segment
		(start 266.121134 -1.851406)
		(end 266.502642 0.312166)
		(width 0.13208)
		(layer "B.Cu")
		(net "DELTA_L_85_10INCH_BOT_DN")
	)
	(segment
		(start 303.812956 -0.120396)
		(end 302.889158 -5.359146)
		(width 0.13208)
		(layer "B.Cu")
		(net "DELTA_L_85_10INCH_BOT_DN")
	)
	(segment
		(start 303.705514 0.032766)
		(end 303.812956 -0.120396)
		(width 0.13208)
		(layer "B.Cu")
		(net "DELTA_L_85_10INCH_BOT_DN")
	)
	(segment
		(start 284.957012 -5.366004)
		(end 285.18358 -5.688838)
		(width 0.13208)
		(layer "B.Cu")
		(net "DELTA_L_85_10INCH_BOT_DN")
	)
	(segment
		(start 267.266166 -5.66674)
		(end 268.701012 -5.919978)
		(width 0.13208)
		(layer "B.Cu")
		(net "DELTA_L_85_10INCH_BOT_DN")
	)
	(segment
		(start 267.986002 0.050292)
		(end 267.035534 -5.338318)
		(width 0.13208)
		(layer "B.Cu")
		(net "DELTA_L_85_10INCH_BOT_DN")
	)
	(segment
		(start 323.323204 -2.789682)
		(end 323.82714 -2.285746)
		(width 0.13208)
		(layer "B.Cu")
		(net "DELTA_L_85_10INCH_BOT_DN")
	)
	(segment
		(start 271.56664 0.023876)
		(end 270.625824 -5.309616)
		(width 0.13208)
		(layer "B.Cu")
		(net "DELTA_L_85_10INCH_BOT_DN")
	)
	(segment
		(start 309.501794 0.152908)
		(end 309.654702 0.260096)
		(width 0.13208)
		(layer "B.Cu")
		(net "DELTA_L_85_10INCH_BOT_DN")
	)
	(segment
		(start 266.502642 0.312166)
		(end 266.655296 0.4191)
		(width 0.13208)
		(layer "B.Cu")
		(net "DELTA_L_85_10INCH_BOT_DN")
	)
	(segment
		(start 280.825194 0.206248)
		(end 280.977848 0.313436)
		(width 0.13208)
		(layer "B.Cu")
		(net "DELTA_L_85_10INCH_BOT_DN")
	)
	(segment
		(start 266.655296 0.4191)
		(end 267.87856 0.203454)
		(width 0.13208)
		(layer "B.Cu")
		(net "DELTA_L_85_10INCH_BOT_DN")
	)
	(segment
		(start 287.997392 0.217932)
		(end 288.1503 0.32512)
		(width 0.13208)
		(layer "B.Cu")
		(net "DELTA_L_85_10INCH_BOT_DN")
	)
	(segment
		(start 279.455626 -5.92709)
		(end 279.784048 -5.696458)
		(width 0.13208)
		(layer "B.Cu")
		(net "DELTA_L_85_10INCH_BOT_DN")
	)
	(segment
		(start 305.9176 0.157734)
		(end 306.070508 0.264922)
		(width 0.13208)
		(layer "B.Cu")
		(net "DELTA_L_85_10INCH_BOT_DN")
	)
	(segment
		(start 282.201112 0.09779)
		(end 282.308554 -0.055372)
		(width 0.13208)
		(layer "B.Cu")
		(net "DELTA_L_85_10INCH_BOT_DN")
	)
	(segment
		(start 302.889158 -5.359146)
		(end 303.119282 -5.687822)
		(width 0.13208)
		(layer "B.Cu")
		(net "DELTA_L_85_10INCH_BOT_DN")
	)
	(segment
		(start 278.727916 -0.028956)
		(end 277.790148 -5.34543)
		(width 0.13208)
		(layer "B.Cu")
		(net "DELTA_L_85_10INCH_BOT_DN")
	)
	(segment
		(start 300.23308 -0.058674)
		(end 299.287946 -5.420106)
		(width 0.13208)
		(layer "B.Cu")
		(net "DELTA_L_85_10INCH_BOT_DN")
	)
	(segment
		(start 298.902882 0.310134)
		(end 300.125892 0.094488)
		(width 0.13208)
		(layer "B.Cu")
		(net "DELTA_L_85_10INCH_BOT_DN")
	)
	(segment
		(start 294.113966 -5.756148)
		(end 295.169336 0.229362)
		(width 0.13208)
		(layer "B.Cu")
		(net "DELTA_L_85_10INCH_BOT_DN")
	)
	(segment
		(start 319.21704 -5.743448)
		(end 320.254122 0.137922)
		(width 0.13208)
		(layer "B.Cu")
		(net "DELTA_L_85_10INCH_BOT_DN")
	)
	(segment
		(start 313.642756 -5.367274)
		(end 313.868816 -5.690362)
		(width 0.13208)
		(layer "B.Cu")
		(net "DELTA_L_85_10INCH_BOT_DN")
	)
	(segment
		(start 288.1503 0.32512)
		(end 289.373564 0.109474)
		(width 0.13208)
		(layer "B.Cu")
		(net "DELTA_L_85_10INCH_BOT_DN")
	)
	(segment
		(start 304.554128 -5.94106)
		(end 304.882804 -5.710682)
		(width 0.13208)
		(layer "B.Cu")
		(net "DELTA_L_85_10INCH_BOT_DN")
	)
	(segment
		(start 315.636402 -5.71881)
		(end 316.673738 0.164846)
		(width 0.13208)
		(layer "B.Cu")
		(net "DELTA_L_85_10INCH_BOT_DN")
	)
	(segment
		(start 286.628078 -5.9436)
		(end 286.950912 -5.717032)
		(width 0.13208)
		(layer "B.Cu")
		(net "DELTA_L_85_10INCH_BOT_DN")
	)
	(segment
		(start 299.287946 -5.420106)
		(end 299.513752 -5.743702)
		(width 0.13208)
		(layer "B.Cu")
		(net "DELTA_L_85_10INCH_BOT_DN")
	)
	(segment
		(start 292.120066 -5.40512)
		(end 292.346634 -5.727954)
		(width 0.13208)
		(layer "B.Cu")
		(net "DELTA_L_85_10INCH_BOT_DN")
	)
	(segment
		(start 277.244556 0.232664)
		(end 277.39721 0.339852)
		(width 0.13208)
		(layer "B.Cu")
		(net "DELTA_L_85_10INCH_BOT_DN")
	)
	(segment
		(start 285.78937 0.1143)
		(end 285.896558 -0.038862)
		(width 0.13208)
		(layer "B.Cu")
		(net "DELTA_L_85_10INCH_BOT_DN")
	)
	(segment
		(start 299.513752 -5.743702)
		(end 300.958504 -5.99821)
		(width 0.13208)
		(layer "B.Cu")
		(net "DELTA_L_85_10INCH_BOT_DN")
	)
	(segment
		(start 275.039836 0.150622)
		(end 275.147278 -0.00254)
		(width 0.13208)
		(layer "B.Cu")
		(net "DELTA_L_85_10INCH_BOT_DN")
	)
	(segment
		(start 295.70934 -5.381244)
		(end 295.935908 -5.704078)
		(width 0.13208)
		(layer "B.Cu")
		(net "DELTA_L_85_10INCH_BOT_DN")
	)
	(segment
		(start 293.082726 0.05334)
		(end 292.120066 -5.40512)
		(width 0.13208)
		(layer "B.Cu")
		(net "DELTA_L_85_10INCH_BOT_DN")
	)
	(segment
		(start 295.169336 0.229362)
		(end 295.322498 0.337058)
		(width 0.13208)
		(layer "B.Cu")
		(net "DELTA_L_85_10INCH_BOT_DN")
	)
	(segment
		(start 284.413198 0.222758)
		(end 284.566106 0.329946)
		(width 0.13208)
		(layer "B.Cu")
		(net "DELTA_L_85_10INCH_BOT_DN")
	)
	(segment
		(start 288.767774 -5.694172)
		(end 290.212272 -5.948934)
		(width 0.13208)
		(layer "B.Cu")
		(net "DELTA_L_85_10INCH_BOT_DN")
	)
	(segment
		(start 275.882354 -5.859526)
		(end 276.210522 -5.628894)
		(width 0.13208)
		(layer "B.Cu")
		(net "DELTA_L_85_10INCH_BOT_DN")
	)
	(segment
		(start 278.620474 0.124206)
		(end 278.727916 -0.028956)
		(width 0.13208)
		(layer "B.Cu")
		(net "DELTA_L_85_10INCH_BOT_DN")
	)
	(segment
		(start 312.051954 -5.716778)
		(end 313.103768 0.249428)
		(width 0.13208)
		(layer "B.Cu")
		(net "DELTA_L_85_10INCH_BOT_DN")
	)
	(segment
		(start 306.070508 0.264922)
		(end 307.293772 0.049276)
		(width 0.13208)
		(layer "B.Cu")
		(net "DELTA_L_85_10INCH_BOT_DN")
	)
	(segment
		(start 323.82714 -2.285746)
		(end 328.17816 -2.285746)
		(width 0.13208)
		(layer "B.Cu")
		(net "DELTA_L_85_10INCH_BOT_DN")
	)
	(segment
		(start 273.816572 0.366268)
		(end 275.039836 0.150622)
		(width 0.13208)
		(layer "B.Cu")
		(net "DELTA_L_85_10INCH_BOT_DN")
	)
	(segment
		(start 274.216876 -5.277358)
		(end 274.447508 -5.606288)
		(width 0.13208)
		(layer "B.Cu")
		(net "DELTA_L_85_10INCH_BOT_DN")
	)
	(segment
		(start 297.380406 -5.95884)
		(end 297.70324 -5.732272)
		(width 0.13208)
		(layer "B.Cu")
		(net "DELTA_L_85_10INCH_BOT_DN")
	)
	(segment
		(start 269.029434 -5.689346)
		(end 270.08328 0.285496)
		(width 0.13208)
		(layer "B.Cu")
		(net "DELTA_L_85_10INCH_BOT_DN")
	)
	(segment
		(start 318.893952 -5.969508)
		(end 319.21704 -5.743448)
		(width 0.13208)
		(layer "B.Cu")
		(net "DELTA_L_85_10INCH_BOT_DN")
	)
	(segment
		(start 302.48225 0.248412)
		(end 303.705514 0.032766)
		(width 0.13208)
		(layer "B.Cu")
		(net "DELTA_L_85_10INCH_BOT_DN")
	)
	(segment
		(start 295.322498 0.336804)
		(end 296.545508 0.121158)
		(width 0.13208)
		(layer "B.Cu")
		(net "DELTA_L_85_10INCH_BOT_DN")
	)
	(segment
		(start 300.125892 0.094488)
		(end 300.23308 -0.058674)
		(width 0.13208)
		(layer "B.Cu")
		(net "DELTA_L_85_10INCH_BOT_DN")
	)
	(segment
		(start 308.464458 -5.729478)
		(end 309.501794 0.152908)
		(width 0.13208)
		(layer "B.Cu")
		(net "DELTA_L_85_10INCH_BOT_DN")
	)
	(segment
		(start 283.038042 -5.94106)
		(end 283.366718 -5.71119)
		(width 0.13208)
		(layer "B.Cu")
		(net "DELTA_L_85_10INCH_BOT_DN")
	)
	(segment
		(start 307.40096 -0.103632)
		(end 306.471066 -5.377942)
		(width 0.13208)
		(layer "B.Cu")
		(net "DELTA_L_85_10INCH_BOT_DN")
	)
	(segment
		(start 298.749974 0.202946)
		(end 298.902882 0.310134)
		(width 0.13208)
		(layer "B.Cu")
		(net "DELTA_L_85_10INCH_BOT_DN")
	)
	(segment
		(start 321.737482 -0.123698)
		(end 320.80581 -5.407406)
		(width 0.13208)
		(layer "B.Cu")
		(net "DELTA_L_85_10INCH_BOT_DN")
	)
	(segment
		(start 290.535106 -5.722366)
		(end 291.599366 0.314452)
		(width 0.13208)
		(layer "B.Cu")
		(net "DELTA_L_85_10INCH_BOT_DN")
	)
	(segment
		(start 273.663918 0.25908)
		(end 273.816572 0.366268)
		(width 0.13208)
		(layer "B.Cu")
		(net "DELTA_L_85_10INCH_BOT_DN")
	)
	(segment
		(start 306.697126 -5.70103)
		(end 308.141624 -5.955538)
		(width 0.13208)
		(layer "B.Cu")
		(net "DELTA_L_85_10INCH_BOT_DN")
	)
	(segment
		(start 289.373564 0.109474)
		(end 289.480752 -0.043688)
		(width 0.13208)
		(layer "B.Cu")
		(net "DELTA_L_85_10INCH_BOT_DN")
	)
	(segment
		(start 309.654702 0.260096)
		(end 310.877966 0.04445)
		(width 0.13208)
		(layer "B.Cu")
		(net "DELTA_L_85_10INCH_BOT_DN")
	)
	(segment
		(start 300.958504 -5.99821)
		(end 301.28718 -5.76834)
		(width 0.13208)
		(layer "B.Cu")
		(net "DELTA_L_85_10INCH_BOT_DN")
	)
	(segment
		(start 317.223394 -5.391912)
		(end 317.449454 -5.715)
		(width 0.13208)
		(layer "B.Cu")
		(net "DELTA_L_85_10INCH_BOT_DN")
	)
	(segment
		(start 296.545508 0.121158)
		(end 296.65295 -0.03175)
		(width 0.13208)
		(layer "B.Cu")
		(net "DELTA_L_85_10INCH_BOT_DN")
	)
	(segment
		(start 302.329596 0.141224)
		(end 302.48225 0.248412)
		(width 0.13208)
		(layer "B.Cu")
		(net "DELTA_L_85_10INCH_BOT_DN")
	)
	(segment
		(start 285.896558 -0.038862)
		(end 284.957012 -5.366004)
		(width 0.13208)
		(layer "B.Cu")
		(net "DELTA_L_85_10INCH_BOT_DN")
	)
	(segment
		(start 301.28718 -5.76834)
		(end 302.329596 0.141224)
		(width 0.13208)
		(layer "B.Cu")
		(net "DELTA_L_85_10INCH_BOT_DN")
	)
	(segment
		(start 278.02078 -5.673852)
		(end 279.455626 -5.92709)
		(width 0.13208)
		(layer "B.Cu")
		(net "DELTA_L_85_10INCH_BOT_DN")
	)
	(segment
		(start 321.630294 0.029464)
		(end 321.737482 -0.123698)
		(width 0.13208)
		(layer "B.Cu")
		(net "DELTA_L_85_10INCH_BOT_DN")
	)
	(segment
		(start 313.103768 0.249428)
		(end 313.25693 0.356616)
		(width 0.13208)
		(layer "B.Cu")
		(net "DELTA_L_85_10INCH_BOT_DN")
	)
	(segment
		(start 317.449454 -5.715)
		(end 318.893952 -5.969508)
		(width 0.13208)
		(layer "B.Cu")
		(net "DELTA_L_85_10INCH_BOT_DN")
	)
	(segment
		(start 292.346634 -5.727954)
		(end 293.791132 -5.982716)
		(width 0.13208)
		(layer "B.Cu")
		(net "DELTA_L_85_10INCH_BOT_DN")
	)
	(segment
		(start 315.313314 -5.94487)
		(end 315.636402 -5.71881)
		(width 0.13208)
		(layer "B.Cu")
		(net "DELTA_L_85_10INCH_BOT_DN")
	)
	(segment
		(start 271.459198 0.177038)
		(end 271.56664 0.023876)
		(width 0.13208)
		(layer "B.Cu")
		(net "DELTA_L_85_10INCH_BOT_DN")
	)
	(segment
		(start 272.619724 -5.660644)
		(end 273.663918 0.25908)
		(width 0.13208)
		(layer "B.Cu")
		(net "DELTA_L_85_10INCH_BOT_DN")
	)
	(segment
		(start 320.407284 0.24511)
		(end 321.630294 0.029464)
		(width 0.13208)
		(layer "B.Cu")
		(net "DELTA_L_85_10INCH_BOT_DN")
	)
	(segment
		(start 270.856456 -5.638038)
		(end 272.291302 -5.891276)
		(width 0.13208)
		(layer "B.Cu")
		(net "DELTA_L_85_10INCH_BOT_DN")
	)
	(segment
		(start 272.291302 -5.891276)
		(end 272.619724 -5.660644)
		(width 0.13208)
		(layer "B.Cu")
		(net "DELTA_L_85_10INCH_BOT_DN")
	)
	(segment
		(start 261.667752 -2.406142)
		(end 261.776464 -2.29743)
		(width 0.13208)
		(layer "B.Cu")
		(net "DELTA_L_85_10INCH_BOT_DN")
	)
	(segment
		(start 277.39721 0.339852)
		(end 278.620474 0.124206)
		(width 0.13208)
		(layer "B.Cu")
		(net "DELTA_L_85_10INCH_BOT_DN")
	)
	(segment
		(start 308.141624 -5.955538)
		(end 308.464458 -5.729478)
		(width 0.13208)
		(layer "B.Cu")
		(net "DELTA_L_85_10INCH_BOT_DN")
	)
	(segment
		(start 276.210522 -5.628894)
		(end 277.244556 0.232664)
		(width 0.13208)
		(layer "B.Cu")
		(net "DELTA_L_85_10INCH_BOT_DN")
	)
	(segment
		(start 270.08328 0.285496)
		(end 270.235934 0.392684)
		(width 0.13208)
		(layer "B.Cu")
		(net "DELTA_L_85_10INCH_BOT_DN")
	)
	(segment
		(start 296.65295 -0.03175)
		(end 295.70934 -5.381244)
		(width 0.13208)
		(layer "B.Cu")
		(net "DELTA_L_85_10INCH_BOT_DN")
	)
	(segment
		(start 268.701012 -5.919978)
		(end 269.029434 -5.689346)
		(width 0.13208)
		(layer "B.Cu")
		(net "DELTA_L_85_10INCH_BOT_DN")
	)
	(segment
		(start 274.447508 -5.606288)
		(end 275.882354 -5.859526)
		(width 0.13208)
		(layer "B.Cu")
		(net "DELTA_L_85_10INCH_BOT_DN")
	)
	(segment
		(start 310.058308 -5.365242)
		(end 310.284368 -5.68833)
		(width 0.13208)
		(layer "B.Cu")
		(net "DELTA_L_85_10INCH_BOT_DN")
	)
	(segment
		(start 283.366718 -5.71119)
		(end 284.413198 0.222758)
		(width 0.13208)
		(layer "B.Cu")
		(net "DELTA_L_85_10INCH_BOT_DN")
	)
	(segment
		(start 270.235934 0.392684)
		(end 271.459198 0.177038)
		(width 0.13208)
		(layer "B.Cu")
		(net "DELTA_L_85_10INCH_BOT_DN")
	)
	(segment
		(start 314.480194 0.14097)
		(end 314.587128 -0.011684)
		(width 0.13208)
		(layer "B.Cu")
		(net "DELTA_L_85_10INCH_BOT_DN")
	)
	(segment
		(start 328.17816 -2.285746)
		(end 328.298556 -2.406142)
		(width 0.13208)
		(layer "B.Cu")
		(net "DELTA_L_85_10INCH_BOT_DN")
	)
	(segment
		(start 292.975792 0.205994)
		(end 293.082726 0.05334)
		(width 0.13208)
		(layer "B.Cu")
		(net "DELTA_L_85_10INCH_BOT_DN")
	)
	(segment
		(start 304.882804 -5.710682)
		(end 305.9176 0.157734)
		(width 0.13208)
		(layer "B.Cu")
		(net "DELTA_L_85_10INCH_BOT_DN")
	)
	(segment
		(start 267.87856 0.203454)
		(end 267.986002 0.050292)
		(width 0.13208)
		(layer "B.Cu")
		(net "DELTA_L_85_10INCH_BOT_DN")
	)
	(segment
		(start 277.790148 -5.34543)
		(end 278.02078 -5.673852)
		(width 0.13208)
		(layer "B.Cu")
		(net "DELTA_L_85_10INCH_BOT_DN")
	)
	(segment
		(start 318.04991 0.056134)
		(end 318.157098 -0.096774)
		(width 0.13208)
		(layer "B.Cu")
		(net "DELTA_L_85_10INCH_BOT_DN")
	)
	(segment
		(start 314.587128 -0.011684)
		(end 313.642756 -5.367274)
		(width 0.13208)
		(layer "B.Cu")
		(net "DELTA_L_85_10INCH_BOT_DN")
	)
	(segment
		(start 313.25693 0.356616)
		(end 314.480194 0.14097)
		(width 0.13208)
		(layer "B.Cu")
		(net "DELTA_L_85_10INCH_BOT_DN")
	)
	(segment
		(start 328.298556 -2.406142)
		(end 328.414888 -2.406142)
		(width 0.13208)
		(layer "B.Cu")
		(net "DELTA_L_85_10INCH_BOT_DN")
	)
	(segment
		(start 288.541206 -5.371338)
		(end 288.767774 -5.694172)
		(width 0.13208)
		(layer "B.Cu")
		(net "DELTA_L_85_10INCH_BOT_DN")
	)
	(segment
		(start 310.284368 -5.68833)
		(end 311.728866 -5.942838)
		(width 0.13208)
		(layer "B.Cu")
		(net "DELTA_L_85_10INCH_BOT_DN")
	)
	(segment
		(start 285.18358 -5.688838)
		(end 286.628078 -5.9436)
		(width 0.13208)
		(layer "B.Cu")
		(net "DELTA_L_85_10INCH_BOT_DN")
	)
	(segment
		(start 313.868816 -5.690362)
		(end 315.313314 -5.94487)
		(width 0.13208)
		(layer "B.Cu")
		(net "DELTA_L_85_10INCH_BOT_DN")
	)
	(segment
		(start 293.791132 -5.982716)
		(end 294.113966 -5.756148)
		(width 0.13208)
		(layer "B.Cu")
		(net "DELTA_L_85_10INCH_BOT_DN")
	)
	(segment
		(start 321.032378 -5.73024)
		(end 322.47713 -5.985002)
		(width 0.13208)
		(layer "B.Cu")
		(net "DELTA_L_85_10INCH_BOT_DN")
	)
	(segment
		(start 322.799964 -5.758434)
		(end 323.323204 -2.789682)
		(width 0.13208)
		(layer "B.Cu")
		(net "DELTA_L_85_10INCH_BOT_DN")
	)
	(segment
		(start 303.119282 -5.687822)
		(end 304.554128 -5.94106)
		(width 0.13208)
		(layer "B.Cu")
		(net "DELTA_L_85_10INCH_BOT_DN")
	)
	(segment
		(start 286.950912 -5.717032)
		(end 287.997392 0.217932)
		(width 0.13208)
		(layer "B.Cu")
		(net "DELTA_L_85_10INCH_BOT_DN")
	)
	(segment
		(start 310.877966 0.04445)
		(end 310.985154 -0.108712)
		(width 0.13208)
		(layer "B.Cu")
		(net "DELTA_L_85_10INCH_BOT_DN")
	)
	(segment
		(start 282.308554 -0.055372)
		(end 281.372818 -5.359908)
		(width 0.13208)
		(layer "B.Cu")
		(net "DELTA_L_85_10INCH_BOT_DN")
	)
	(segment
		(start 306.471066 -5.377942)
		(end 306.697126 -5.70103)
		(width 0.13208)
		(layer "B.Cu")
		(net "DELTA_L_85_10INCH_BOT_DN")
	)
	(segment
		(start 307.293772 0.049276)
		(end 307.40096 -0.103632)
		(width 0.13208)
		(layer "B.Cu")
		(net "DELTA_L_85_10INCH_BOT_DN")
	)
	(segment
		(start 280.977848 0.313436)
		(end 282.201112 0.09779)
		(width 0.13208)
		(layer "B.Cu")
		(net "DELTA_L_85_10INCH_BOT_DN")
	)
	(segment
		(start 311.728866 -5.942838)
		(end 312.051954 -5.716778)
		(width 0.13208)
		(layer "B.Cu")
		(net "DELTA_L_85_10INCH_BOT_DN")
	)
	(segment
		(start 261.776464 -2.29743)
		(end 265.589258 -2.29743)
		(width 0.13208)
		(layer "B.Cu")
		(net "DELTA_L_85_10INCH_BOT_DN")
	)
	(segment
		(start 291.752528 0.42164)
		(end 292.975792 0.205994)
		(width 0.13208)
		(layer "B.Cu")
		(net "DELTA_L_85_10INCH_BOT_DN")
	)
	(segment
		(start 318.157098 -0.096774)
		(end 317.223394 -5.391912)
		(width 0.13208)
		(layer "B.Cu")
		(net "DELTA_L_85_10INCH_BOT_DN")
	)
	(segment
		(start 316.673738 0.164846)
		(end 316.8269 0.272034)
		(width 0.13208)
		(layer "B.Cu")
		(net "DELTA_L_85_10INCH_BOT_DN")
	)
	(via
		(at 83.34248 -180.558948)
		(size 0.508)
		(drill 0.254)
		(layers "F.Cu" "B.Cu")
		(net "DBP_CPU_MBP1_GTL_N")
	)
	(via
		(at 72.226932 -186.070748)
		(size 0.508)
		(drill 0.254)
		(layers "F.Cu" "B.Cu")
		(net "DBP_CPU_MBP1_GTL_N")
	)
	(via
		(at 261.78764 -186.710828)
		(size 0.508)
		(drill 0.254)
		(layers "F.Cu" "B.Cu")
		(net "DBP_CPU_MBP1_GTL_N")
	)
	(via
		(at 285.52648 -163.515548)
		(size 0.508)
		(drill 0.254)
		(layers "F.Cu" "B.Cu")
		(net "DBP_CPU_MBP1_GTL_N")
	)
	(segment
		(start 72.953118 -188.0108)
		(end 73.485756 -188.543438)
		(width 0.12954)
		(layer "B.Cu")
		(net "DBP_CPU_MBP1_GTL_N")
	)
	(segment
		(start 74.347324 -189.296294)
		(end 74.347324 -190.305182)
		(width 0.12954)
		(layer "B.Cu")
		(net "DBP_CPU_MBP1_GTL_N")
	)
	(segment
		(start 336.000852 -185.227976)
		(end 335.741264 -185.227976)
		(width 0.12954)
		(layer "B.Cu")
		(net "DBP_CPU_MBP1_GTL_N")
	)
	(segment
		(start 336.47888 -184.749948)
		(end 336.000852 -185.227976)
		(width 0.12954)
		(layer "B.Cu")
		(net "DBP_CPU_MBP1_GTL_N")
	)
	(segment
		(start 72.953118 -187.25007)
		(end 72.953118 -188.0108)
		(width 0.12954)
		(layer "B.Cu")
		(net "DBP_CPU_MBP1_GTL_N")
	)
	(segment
		(start 334.662018 -189.80277)
		(end 334.662018 -189.32652)
		(width 0.12954)
		(layer "B.Cu")
		(net "DBP_CPU_MBP1_GTL_N")
	)
	(segment
		(start 334.662018 -189.32652)
		(end 335.197958 -188.79058)
		(width 0.12954)
		(layer "B.Cu")
		(net "DBP_CPU_MBP1_GTL_N")
	)
	(segment
		(start 72.655684 -183.703976)
		(end 72.655684 -184.53989)
		(width 0.12954)
		(layer "B.Cu")
		(net "DBP_CPU_MBP1_GTL_N")
	)
	(segment
		(start 336.47888 -180.882798)
		(end 336.47888 -184.749948)
		(width 0.12954)
		(layer "B.Cu")
		(net "DBP_CPU_MBP1_GTL_N")
	)
	(segment
		(start 73.485756 -188.543438)
		(end 73.79081 -188.543438)
		(width 0.12954)
		(layer "B.Cu")
		(net "DBP_CPU_MBP1_GTL_N")
	)
	(segment
		(start 335.741264 -186.169554)
		(end 335.741264 -185.227976)
		(width 0.12954)
		(layer "B.Cu")
		(net "DBP_CPU_MBP1_GTL_N")
	)
	(segment
		(start 308.67985 -157.683708)
		(end 320.681858 -169.685716)
		(width 0.12954)
		(layer "B.Cu")
		(net "DBP_CPU_MBP1_GTL_N")
	)
	(segment
		(start 291.35832 -157.683708)
		(end 308.67985 -157.683708)
		(width 0.12954)
		(layer "B.Cu")
		(net "DBP_CPU_MBP1_GTL_N")
	)
	(segment
		(start 72.5678 -184.627774)
		(end 72.5678 -185.72988)
		(width 0.12954)
		(layer "B.Cu")
		(net "DBP_CPU_MBP1_GTL_N")
	)
	(segment
		(start 72.226932 -186.523884)
		(end 72.953118 -187.25007)
		(width 0.12954)
		(layer "B.Cu")
		(net "DBP_CPU_MBP1_GTL_N")
	)
	(segment
		(start 320.681858 -169.685716)
		(end 325.281798 -169.685716)
		(width 0.12954)
		(layer "B.Cu")
		(net "DBP_CPU_MBP1_GTL_N")
	)
	(segment
		(start 72.655684 -184.53989)
		(end 72.5678 -184.627774)
		(width 0.12954)
		(layer "B.Cu")
		(net "DBP_CPU_MBP1_GTL_N")
	)
	(segment
		(start 73.79081 -188.543438)
		(end 74.20864 -188.961268)
		(width 0.12954)
		(layer "B.Cu")
		(net "DBP_CPU_MBP1_GTL_N")
	)
	(segment
		(start 74.20864 -188.961268)
		(end 74.347324 -189.296294)
		(width 0.12954)
		(layer "B.Cu")
		(net "DBP_CPU_MBP1_GTL_N")
	)
	(segment
		(start 325.281798 -169.685716)
		(end 336.47888 -180.882798)
		(width 0.12954)
		(layer "B.Cu")
		(net "DBP_CPU_MBP1_GTL_N")
	)
	(segment
		(start 335.197958 -188.79058)
		(end 335.197958 -186.71286)
		(width 0.12954)
		(layer "B.Cu")
		(net "DBP_CPU_MBP1_GTL_N")
	)
	(segment
		(start 72.226932 -186.070748)
		(end 72.226932 -186.523884)
		(width 0.12954)
		(layer "B.Cu")
		(net "DBP_CPU_MBP1_GTL_N")
	)
	(segment
		(start 335.197958 -186.71286)
		(end 335.741264 -186.169554)
		(width 0.12954)
		(layer "B.Cu")
		(net "DBP_CPU_MBP1_GTL_N")
	)
	(segment
		(start 72.5678 -185.72988)
		(end 72.226932 -186.070748)
		(width 0.12954)
		(layer "B.Cu")
		(net "DBP_CPU_MBP1_GTL_N")
	)
	(segment
		(start 285.52648 -163.515548)
		(end 291.35832 -157.683708)
		(width 0.12954)
		(layer "B.Cu")
		(net "DBP_CPU_MBP1_GTL_N")
	)
	(segment
		(start 335.288128 -190.42888)
		(end 334.662018 -189.80277)
		(width 0.12954)
		(layer "B.Cu")
		(net "DBP_CPU_MBP1_GTL_N")
	)
	(segment
		(start 261.95274 -186.545728)
		(end 261.78764 -186.710828)
		(width 0.127)
		(layer "In2.Cu")
		(net "DBP_CPU_MBP1_GTL_N")
	)
	(segment
		(start 280.19248 -163.515548)
		(end 261.95274 -181.755288)
		(width 0.127)
		(layer "In2.Cu")
		(net "DBP_CPU_MBP1_GTL_N")
	)
	(segment
		(start 261.95274 -181.755288)
		(end 261.95274 -186.545728)
		(width 0.127)
		(layer "In2.Cu")
		(net "DBP_CPU_MBP1_GTL_N")
	)
	(segment
		(start 285.52648 -163.515548)
		(end 280.19248 -163.515548)
		(width 0.127)
		(layer "In2.Cu")
		(net "DBP_CPU_MBP1_GTL_N")
	)
	(segment
		(start 74.30008 -181.549548)
		(end 74.30008 -182.895494)
		(width 0.127)
		(layer "In11.Cu")
		(net "DBP_CPU_MBP1_GTL_N")
	)
	(segment
		(start 72.5424 -184.653174)
		(end 72.5424 -185.75528)
		(width 0.127)
		(layer "In11.Cu")
		(net "DBP_CPU_MBP1_GTL_N")
	)
	(segment
		(start 83.34248 -180.558948)
		(end 83.13928 -180.355748)
		(width 0.127)
		(layer "In11.Cu")
		(net "DBP_CPU_MBP1_GTL_N")
	)
	(segment
		(start 83.13928 -180.355748)
		(end 75.49388 -180.355748)
		(width 0.127)
		(layer "In11.Cu")
		(net "DBP_CPU_MBP1_GTL_N")
	)
	(segment
		(start 74.30008 -182.895494)
		(end 72.5424 -184.653174)
		(width 0.127)
		(layer "In11.Cu")
		(net "DBP_CPU_MBP1_GTL_N")
	)
	(segment
		(start 75.49388 -180.355748)
		(end 74.30008 -181.549548)
		(width 0.127)
		(layer "In11.Cu")
		(net "DBP_CPU_MBP1_GTL_N")
	)
	(segment
		(start 72.5424 -185.75528)
		(end 72.226932 -186.070748)
		(width 0.127)
		(layer "In11.Cu")
		(net "DBP_CPU_MBP1_GTL_N")
	)
	(segment
		(start 214.524844 -192.344548)
		(end 213.89848 -191.718184)
		(width 0.127)
		(layer "In13.Cu")
		(net "DBP_CPU_MBP1_GTL_N")
	)
	(segment
		(start 212.061298 -191.718184)
		(end 209.317844 -188.97473)
		(width 0.127)
		(layer "In13.Cu")
		(net "DBP_CPU_MBP1_GTL_N")
	)
	(segment
		(start 83.34248 -180.558694)
		(end 83.34248 -180.558948)
		(width 0.127)
		(layer "In13.Cu")
		(net "DBP_CPU_MBP1_GTL_N")
	)
	(segment
		(start 83.536028 -180.752242)
		(end 83.34248 -180.558694)
		(width 0.127)
		(layer "In13.Cu")
		(net "DBP_CPU_MBP1_GTL_N")
	)
	(segment
		(start 261.78764 -186.710828)
		(end 261.40156 -186.324748)
		(width 0.127)
		(layer "In13.Cu")
		(net "DBP_CPU_MBP1_GTL_N")
	)
	(segment
		(start 90.094816 -180.752242)
		(end 83.536028 -180.752242)
		(width 0.127)
		(layer "In13.Cu")
		(net "DBP_CPU_MBP1_GTL_N")
	)
	(segment
		(start 209.317844 -188.97473)
		(end 209.317844 -187.65647)
		(width 0.127)
		(layer "In13.Cu")
		(net "DBP_CPU_MBP1_GTL_N")
	)
	(segment
		(start 206.673958 -185.012584)
		(end 94.355158 -185.012584)
		(width 0.127)
		(layer "In13.Cu")
		(net "DBP_CPU_MBP1_GTL_N")
	)
	(segment
		(start 223.22028 -189.652148)
		(end 220.52788 -192.344548)
		(width 0.127)
		(layer "In13.Cu")
		(net "DBP_CPU_MBP1_GTL_N")
	)
	(segment
		(start 220.52788 -192.344548)
		(end 214.524844 -192.344548)
		(width 0.127)
		(layer "In13.Cu")
		(net "DBP_CPU_MBP1_GTL_N")
	)
	(segment
		(start 223.22028 -187.620148)
		(end 223.22028 -189.652148)
		(width 0.127)
		(layer "In13.Cu")
		(net "DBP_CPU_MBP1_GTL_N")
	)
	(segment
		(start 261.40156 -186.324748)
		(end 224.51568 -186.324748)
		(width 0.127)
		(layer "In13.Cu")
		(net "DBP_CPU_MBP1_GTL_N")
	)
	(segment
		(start 224.51568 -186.324748)
		(end 223.22028 -187.620148)
		(width 0.127)
		(layer "In13.Cu")
		(net "DBP_CPU_MBP1_GTL_N")
	)
	(segment
		(start 94.355158 -185.012584)
		(end 90.094816 -180.752242)
		(width 0.127)
		(layer "In13.Cu")
		(net "DBP_CPU_MBP1_GTL_N")
	)
	(segment
		(start 213.89848 -191.718184)
		(end 212.061298 -191.718184)
		(width 0.127)
		(layer "In13.Cu")
		(net "DBP_CPU_MBP1_GTL_N")
	)
	(segment
		(start 209.317844 -187.65647)
		(end 206.673958 -185.012584)
		(width 0.127)
		(layer "In13.Cu")
		(net "DBP_CPU_MBP1_GTL_N")
	)
	(via
		(at 333.10068 -187.518548)
		(size 0.508)
		(drill 0.254)
		(layers "F.Cu" "B.Cu")
		(net "DBP_CPU_MBP0_GTL_N")
	)
	(via
		(at 91.69146 -184.622948)
		(size 0.508)
		(drill 0.254)
		(layers "F.Cu" "B.Cu")
		(net "DBP_CPU_MBP0_GTL_N")
	)
	(via
		(at 263.386316 -186.605926)
		(size 0.508)
		(drill 0.254)
		(layers "F.Cu" "B.Cu")
		(net "DBP_CPU_MBP0_GTL_N")
	)
	(via
		(at 267.65123 -188.554614)
		(size 0.508)
		(drill 0.254)
		(layers "F.Cu" "B.Cu")
		(net "DBP_CPU_MBP0_GTL_N")
	)
	(via
		(at 80.763618 -189.73419)
		(size 0.508)
		(drill 0.254)
		(layers "F.Cu" "B.Cu")
		(net "DBP_CPU_MBP0_GTL_N")
	)
	(via
		(at 217.55608 -190.820548)
		(size 0.508)
		(drill 0.254)
		(layers "F.Cu" "B.Cu")
		(net "DBP_CPU_MBP0_GTL_N")
	)
	(via
		(at 196.09308 -189.626748)
		(size 0.508)
		(drill 0.254)
		(layers "F.Cu" "B.Cu")
		(net "DBP_CPU_MBP0_GTL_N")
	)
	(segment
		(start 333.10068 -187.518548)
		(end 333.10068 -186.204098)
		(width 0.12954)
		(layer "B.Cu")
		(net "DBP_CPU_MBP0_GTL_N")
	)
	(segment
		(start 333.10068 -189.102492)
		(end 333.10068 -187.518548)
		(width 0.12954)
		(layer "B.Cu")
		(net "DBP_CPU_MBP0_GTL_N")
	)
	(segment
		(start 334.341978 -190.42888)
		(end 333.653638 -189.74054)
		(width 0.12954)
		(layer "B.Cu")
		(net "DBP_CPU_MBP0_GTL_N")
	)
	(segment
		(start 267.65123 -188.554614)
		(end 267.232892 -188.136276)
		(width 0.12954)
		(layer "B.Cu")
		(net "DBP_CPU_MBP0_GTL_N")
	)
	(segment
		(start 80.763618 -188.952886)
		(end 80.763618 -189.73419)
		(width 0.12954)
		(layer "B.Cu")
		(net "DBP_CPU_MBP0_GTL_N")
	)
	(segment
		(start 333.322168 -189.32398)
		(end 333.10068 -189.102492)
		(width 0.12954)
		(layer "B.Cu")
		(net "DBP_CPU_MBP0_GTL_N")
	)
	(segment
		(start 333.653638 -189.32398)
		(end 333.322168 -189.32398)
		(width 0.12954)
		(layer "B.Cu")
		(net "DBP_CPU_MBP0_GTL_N")
	)
	(segment
		(start 333.10068 -186.204098)
		(end 333.535528 -185.76925)
		(width 0.12954)
		(layer "B.Cu")
		(net "DBP_CPU_MBP0_GTL_N")
	)
	(segment
		(start 333.653638 -189.74054)
		(end 333.653638 -189.32398)
		(width 0.12954)
		(layer "B.Cu")
		(net "DBP_CPU_MBP0_GTL_N")
	)
	(segment
		(start 267.02893 -188.136276)
		(end 265.49858 -186.605926)
		(width 0.12954)
		(layer "B.Cu")
		(net "DBP_CPU_MBP0_GTL_N")
	)
	(segment
		(start 80.763618 -189.73419)
		(end 80.763618 -190.43396)
		(width 0.12954)
		(layer "B.Cu")
		(net "DBP_CPU_MBP0_GTL_N")
	)
	(segment
		(start 267.232892 -188.136276)
		(end 267.02893 -188.136276)
		(width 0.12954)
		(layer "B.Cu")
		(net "DBP_CPU_MBP0_GTL_N")
	)
	(segment
		(start 265.49858 -186.605926)
		(end 263.386316 -186.605926)
		(width 0.12954)
		(layer "B.Cu")
		(net "DBP_CPU_MBP0_GTL_N")
	)
	(segment
		(start 201.42454 -190.213488)
		(end 203.887832 -187.750196)
		(width 0.127)
		(layer "In11.Cu")
		(net "DBP_CPU_MBP0_GTL_N")
	)
	(segment
		(start 216.479374 -188.543946)
		(end 216.479374 -189.743842)
		(width 0.127)
		(layer "In11.Cu")
		(net "DBP_CPU_MBP0_GTL_N")
	)
	(segment
		(start 216.479374 -189.743842)
		(end 217.55608 -190.820548)
		(width 0.127)
		(layer "In11.Cu")
		(net "DBP_CPU_MBP0_GTL_N")
	)
	(segment
		(start 91.59748 -190.668148)
		(end 81.697576 -190.668148)
		(width 0.127)
		(layer "In11.Cu")
		(net "DBP_CPU_MBP0_GTL_N")
	)
	(segment
		(start 203.887832 -187.750196)
		(end 215.685624 -187.750196)
		(width 0.127)
		(layer "In11.Cu")
		(net "DBP_CPU_MBP0_GTL_N")
	)
	(segment
		(start 92.56268 -189.702948)
		(end 91.59748 -190.668148)
		(width 0.127)
		(layer "In11.Cu")
		(net "DBP_CPU_MBP0_GTL_N")
	)
	(segment
		(start 92.56268 -185.740548)
		(end 92.56268 -189.702948)
		(width 0.127)
		(layer "In11.Cu")
		(net "DBP_CPU_MBP0_GTL_N")
	)
	(segment
		(start 196.67982 -190.213488)
		(end 201.42454 -190.213488)
		(width 0.127)
		(layer "In11.Cu")
		(net "DBP_CPU_MBP0_GTL_N")
	)
	(segment
		(start 81.697576 -190.668148)
		(end 80.763618 -189.73419)
		(width 0.127)
		(layer "In11.Cu")
		(net "DBP_CPU_MBP0_GTL_N")
	)
	(segment
		(start 91.69146 -184.622948)
		(end 91.69146 -184.869328)
		(width 0.127)
		(layer "In11.Cu")
		(net "DBP_CPU_MBP0_GTL_N")
	)
	(segment
		(start 215.685624 -187.750196)
		(end 216.479374 -188.543946)
		(width 0.127)
		(layer "In11.Cu")
		(net "DBP_CPU_MBP0_GTL_N")
	)
	(segment
		(start 196.09308 -189.626748)
		(end 196.67982 -190.213488)
		(width 0.127)
		(layer "In11.Cu")
		(net "DBP_CPU_MBP0_GTL_N")
	)
	(segment
		(start 91.69146 -184.869328)
		(end 92.56268 -185.740548)
		(width 0.127)
		(layer "In11.Cu")
		(net "DBP_CPU_MBP0_GTL_N")
	)
	(segment
		(start 314.854336 -188.715396)
		(end 312.880756 -190.688976)
		(width 0.127)
		(layer "In13.Cu")
		(net "DBP_CPU_MBP0_GTL_N")
	)
	(segment
		(start 263.386316 -185.952638)
		(end 262.691626 -185.257948)
		(width 0.127)
		(layer "In13.Cu")
		(net "DBP_CPU_MBP0_GTL_N")
	)
	(segment
		(start 222.12808 -189.271148)
		(end 220.01988 -191.379348)
		(width 0.127)
		(layer "In13.Cu")
		(net "DBP_CPU_MBP0_GTL_N")
	)
	(segment
		(start 321.697096 -188.715396)
		(end 314.854336 -188.715396)
		(width 0.127)
		(layer "In13.Cu")
		(net "DBP_CPU_MBP0_GTL_N")
	)
	(segment
		(start 95.25508 -188.432948)
		(end 91.69146 -184.869328)
		(width 0.127)
		(layer "In13.Cu")
		(net "DBP_CPU_MBP0_GTL_N")
	)
	(segment
		(start 161.77768 -186.858148)
		(end 99.59848 -186.858148)
		(width 0.127)
		(layer "In13.Cu")
		(net "DBP_CPU_MBP0_GTL_N")
	)
	(segment
		(start 301.918878 -193.456052)
		(end 299.023024 -190.560198)
		(width 0.127)
		(layer "In13.Cu")
		(net "DBP_CPU_MBP0_GTL_N")
	)
	(segment
		(start 218.11488 -191.379348)
		(end 217.55608 -190.820548)
		(width 0.127)
		(layer "In13.Cu")
		(net "DBP_CPU_MBP0_GTL_N")
	)
	(segment
		(start 309.598314 -190.688976)
		(end 306.831238 -193.456052)
		(width 0.127)
		(layer "In13.Cu")
		(net "DBP_CPU_MBP0_GTL_N")
	)
	(segment
		(start 299.023024 -190.560198)
		(end 272.080482 -190.560198)
		(width 0.127)
		(layer "In13.Cu")
		(net "DBP_CPU_MBP0_GTL_N")
	)
	(segment
		(start 99.59848 -186.858148)
		(end 98.02368 -188.432948)
		(width 0.127)
		(layer "In13.Cu")
		(net "DBP_CPU_MBP0_GTL_N")
	)
	(segment
		(start 222.12808 -187.239148)
		(end 222.12808 -189.271148)
		(width 0.127)
		(layer "In13.Cu")
		(net "DBP_CPU_MBP0_GTL_N")
	)
	(segment
		(start 224.10928 -185.257948)
		(end 222.12808 -187.239148)
		(width 0.127)
		(layer "In13.Cu")
		(net "DBP_CPU_MBP0_GTL_N")
	)
	(segment
		(start 272.080482 -190.560198)
		(end 269.935452 -188.415168)
		(width 0.127)
		(layer "In13.Cu")
		(net "DBP_CPU_MBP0_GTL_N")
	)
	(segment
		(start 312.880756 -190.688976)
		(end 309.598314 -190.688976)
		(width 0.127)
		(layer "In13.Cu")
		(net "DBP_CPU_MBP0_GTL_N")
	)
	(segment
		(start 262.691626 -185.257948)
		(end 224.10928 -185.257948)
		(width 0.127)
		(layer "In13.Cu")
		(net "DBP_CPU_MBP0_GTL_N")
	)
	(segment
		(start 193.57848 -192.141348)
		(end 167.06088 -192.141348)
		(width 0.127)
		(layer "In13.Cu")
		(net "DBP_CPU_MBP0_GTL_N")
	)
	(segment
		(start 98.02368 -188.432948)
		(end 95.25508 -188.432948)
		(width 0.127)
		(layer "In13.Cu")
		(net "DBP_CPU_MBP0_GTL_N")
	)
	(segment
		(start 263.386316 -186.605926)
		(end 263.386316 -185.952638)
		(width 0.127)
		(layer "In13.Cu")
		(net "DBP_CPU_MBP0_GTL_N")
	)
	(segment
		(start 91.69146 -184.869328)
		(end 91.69146 -184.622948)
		(width 0.127)
		(layer "In13.Cu")
		(net "DBP_CPU_MBP0_GTL_N")
	)
	(segment
		(start 196.09308 -189.626748)
		(end 193.57848 -192.141348)
		(width 0.127)
		(layer "In13.Cu")
		(net "DBP_CPU_MBP0_GTL_N")
	)
	(segment
		(start 322.893944 -187.518548)
		(end 321.697096 -188.715396)
		(width 0.127)
		(layer "In13.Cu")
		(net "DBP_CPU_MBP0_GTL_N")
	)
	(segment
		(start 269.935452 -188.415168)
		(end 267.790676 -188.415168)
		(width 0.127)
		(layer "In13.Cu")
		(net "DBP_CPU_MBP0_GTL_N")
	)
	(segment
		(start 220.01988 -191.379348)
		(end 218.11488 -191.379348)
		(width 0.127)
		(layer "In13.Cu")
		(net "DBP_CPU_MBP0_GTL_N")
	)
	(segment
		(start 267.790676 -188.415168)
		(end 267.65123 -188.554614)
		(width 0.127)
		(layer "In13.Cu")
		(net "DBP_CPU_MBP0_GTL_N")
	)
	(segment
		(start 333.10068 -187.518548)
		(end 322.893944 -187.518548)
		(width 0.127)
		(layer "In13.Cu")
		(net "DBP_CPU_MBP0_GTL_N")
	)
	(segment
		(start 306.831238 -193.456052)
		(end 301.918878 -193.456052)
		(width 0.127)
		(layer "In13.Cu")
		(net "DBP_CPU_MBP0_GTL_N")
	)
	(segment
		(start 167.06088 -192.141348)
		(end 161.77768 -186.858148)
		(width 0.127)
		(layer "In13.Cu")
		(net "DBP_CPU_MBP0_GTL_N")
	)
	(segment
		(start 364.71352 -66.421254)
		(end 362.20908 -66.421254)
		(width 0.12954)
		(layer "F.Cu")
		(net "DBP_CPU_HOOK9_MBP3_GTL_QS_N")
	)
	(via
		(at 262.589518 -186.845448)
		(size 0.508)
		(drill 0.254)
		(layers "F.Cu" "B.Cu")
		(net "DBP_CPU_HOOK9_MBP3_GTL_QS_N")
	)
	(via
		(at 286.87268 -163.591748)
		(size 0.508)
		(drill 0.254)
		(layers "F.Cu" "B.Cu")
		(net "DBP_CPU_HOOK9_MBP3_GTL_QS_N")
	)
	(via
		(at 362.20908 -66.421254)
		(size 0.508)
		(drill 0.254)
		(layers "F.Cu" "B.Cu")
		(net "DBP_CPU_HOOK9_MBP3_GTL_QS_N")
	)
	(via
		(at 69.658738 -184.69991)
		(size 0.508)
		(drill 0.254)
		(layers "F.Cu" "B.Cu")
		(net "DBP_CPU_HOOK9_MBP3_GTL_QS_N")
	)
	(via
		(at 306.11191 -96.764348)
		(size 0.508)
		(drill 0.254)
		(layers "F.Cu" "B.Cu")
		(net "DBP_CPU_HOOK9_MBP3_GTL_QS_N")
	)
	(via
		(at 84.160106 -180.165502)
		(size 0.508)
		(drill 0.254)
		(layers "F.Cu" "B.Cu")
		(net "DBP_CPU_HOOK9_MBP3_GTL_QS_N")
	)
	(segment
		(start 332.61808 -179.568348)
		(end 332.61808 -188.813948)
		(width 0.12954)
		(layer "B.Cu")
		(net "DBP_CPU_HOOK9_MBP3_GTL_QS_N")
	)
	(segment
		(start 320.361564 -171.897548)
		(end 324.94728 -171.897548)
		(width 0.12954)
		(layer "B.Cu")
		(net "DBP_CPU_HOOK9_MBP3_GTL_QS_N")
	)
	(segment
		(start 297.33748 -163.947348)
		(end 299.19168 -162.093148)
		(width 0.12954)
		(layer "B.Cu")
		(net "DBP_CPU_HOOK9_MBP3_GTL_QS_N")
	)
	(segment
		(start 286.87268 -163.591748)
		(end 287.22828 -163.947348)
		(width 0.12954)
		(layer "B.Cu")
		(net "DBP_CPU_HOOK9_MBP3_GTL_QS_N")
	)
	(segment
		(start 332.447138 -188.98489)
		(end 332.447138 -190.42888)
		(width 0.12954)
		(layer "B.Cu")
		(net "DBP_CPU_HOOK9_MBP3_GTL_QS_N")
	)
	(segment
		(start 70.369684 -185.391806)
		(end 69.353684 -185.391806)
		(width 0.12954)
		(layer "B.Cu")
		(net "DBP_CPU_HOOK9_MBP3_GTL_QS_N")
	)
	(segment
		(start 324.94728 -171.897548)
		(end 332.61808 -179.568348)
		(width 0.12954)
		(layer "B.Cu")
		(net "DBP_CPU_HOOK9_MBP3_GTL_QS_N")
	)
	(segment
		(start 69.658738 -184.69991)
		(end 69.353684 -185.004964)
		(width 0.12954)
		(layer "B.Cu")
		(net "DBP_CPU_HOOK9_MBP3_GTL_QS_N")
	)
	(segment
		(start 332.61808 -188.813948)
		(end 332.447138 -188.98489)
		(width 0.12954)
		(layer "B.Cu")
		(net "DBP_CPU_HOOK9_MBP3_GTL_QS_N")
	)
	(segment
		(start 310.557164 -162.093148)
		(end 320.361564 -171.897548)
		(width 0.12954)
		(layer "B.Cu")
		(net "DBP_CPU_HOOK9_MBP3_GTL_QS_N")
	)
	(segment
		(start 299.19168 -162.093148)
		(end 310.557164 -162.093148)
		(width 0.12954)
		(layer "B.Cu")
		(net "DBP_CPU_HOOK9_MBP3_GTL_QS_N")
	)
	(segment
		(start 69.353684 -185.004964)
		(end 69.353684 -185.391806)
		(width 0.12954)
		(layer "B.Cu")
		(net "DBP_CPU_HOOK9_MBP3_GTL_QS_N")
	)
	(segment
		(start 287.22828 -163.947348)
		(end 297.33748 -163.947348)
		(width 0.12954)
		(layer "B.Cu")
		(net "DBP_CPU_HOOK9_MBP3_GTL_QS_N")
	)
	(segment
		(start 286.87268 -161.331148)
		(end 286.87268 -163.591748)
		(width 0.127)
		(layer "In2.Cu")
		(net "DBP_CPU_HOOK9_MBP3_GTL_QS_N")
	)
	(segment
		(start 306.11191 -96.764348)
		(end 300.66488 -102.211378)
		(width 0.127)
		(layer "In2.Cu")
		(net "DBP_CPU_HOOK9_MBP3_GTL_QS_N")
	)
	(segment
		(start 286.16148 -164.302948)
		(end 282.63088 -164.302948)
		(width 0.127)
		(layer "In2.Cu")
		(net "DBP_CPU_HOOK9_MBP3_GTL_QS_N")
	)
	(segment
		(start 293.944548 -156.51988)
		(end 293.79418 -156.670248)
		(width 0.127)
		(layer "In2.Cu")
		(net "DBP_CPU_HOOK9_MBP3_GTL_QS_N")
	)
	(segment
		(start 286.87268 -163.591748)
		(end 286.16148 -164.302948)
		(width 0.127)
		(layer "In2.Cu")
		(net "DBP_CPU_HOOK9_MBP3_GTL_QS_N")
	)
	(segment
		(start 291.53358 -156.670248)
		(end 286.87268 -161.331148)
		(width 0.127)
		(layer "In2.Cu")
		(net "DBP_CPU_HOOK9_MBP3_GTL_QS_N")
	)
	(segment
		(start 298.31538 -154.709368)
		(end 293.944548 -156.51988)
		(width 0.127)
		(layer "In2.Cu")
		(net "DBP_CPU_HOOK9_MBP3_GTL_QS_N")
	)
	(segment
		(start 282.63088 -164.302948)
		(end 262.589518 -184.34431)
		(width 0.127)
		(layer "In2.Cu")
		(net "DBP_CPU_HOOK9_MBP3_GTL_QS_N")
	)
	(segment
		(start 262.589518 -184.34431)
		(end 262.589518 -186.845448)
		(width 0.127)
		(layer "In2.Cu")
		(net "DBP_CPU_HOOK9_MBP3_GTL_QS_N")
	)
	(segment
		(start 300.66488 -102.211378)
		(end 300.66488 -152.359868)
		(width 0.127)
		(layer "In2.Cu")
		(net "DBP_CPU_HOOK9_MBP3_GTL_QS_N")
	)
	(segment
		(start 293.79418 -156.670248)
		(end 291.53358 -156.670248)
		(width 0.127)
		(layer "In2.Cu")
		(net "DBP_CPU_HOOK9_MBP3_GTL_QS_N")
	)
	(segment
		(start 300.66488 -152.359868)
		(end 298.31538 -154.709368)
		(width 0.127)
		(layer "In2.Cu")
		(net "DBP_CPU_HOOK9_MBP3_GTL_QS_N")
	)
	(segment
		(start 309.92445 -92.951808)
		(end 306.11191 -96.764348)
		(width 0.127)
		(layer "In4.Cu")
		(net "DBP_CPU_HOOK9_MBP3_GTL_QS_N")
	)
	(segment
		(start 316.551056 -92.951808)
		(end 309.92445 -92.951808)
		(width 0.127)
		(layer "In4.Cu")
		(net "DBP_CPU_HOOK9_MBP3_GTL_QS_N")
	)
	(segment
		(start 346.00388 -88.331548)
		(end 327.705466 -88.331548)
		(width 0.127)
		(layer "In4.Cu")
		(net "DBP_CPU_HOOK9_MBP3_GTL_QS_N")
	)
	(segment
		(start 362.18368 -72.151748)
		(end 346.00388 -88.331548)
		(width 0.127)
		(layer "In4.Cu")
		(net "DBP_CPU_HOOK9_MBP3_GTL_QS_N")
	)
	(segment
		(start 327.705466 -88.331548)
		(end 316.551056 -92.951808)
		(width 0.127)
		(layer "In4.Cu")
		(net "DBP_CPU_HOOK9_MBP3_GTL_QS_N")
	)
	(segment
		(start 362.18368 -66.446654)
		(end 362.18368 -72.151748)
		(width 0.127)
		(layer "In4.Cu")
		(net "DBP_CPU_HOOK9_MBP3_GTL_QS_N")
	)
	(segment
		(start 362.20908 -66.421254)
		(end 362.18368 -66.446654)
		(width 0.127)
		(layer "In4.Cu")
		(net "DBP_CPU_HOOK9_MBP3_GTL_QS_N")
	)
	(segment
		(start 69.658738 -183.37149)
		(end 69.658738 -184.69991)
		(width 0.127)
		(layer "In11.Cu")
		(net "DBP_CPU_HOOK9_MBP3_GTL_QS_N")
	)
	(segment
		(start 73.36028 -179.669948)
		(end 69.658738 -183.37149)
		(width 0.127)
		(layer "In11.Cu")
		(net "DBP_CPU_HOOK9_MBP3_GTL_QS_N")
	)
	(segment
		(start 84.160106 -180.165502)
		(end 83.664552 -179.669948)
		(width 0.127)
		(layer "In11.Cu")
		(net "DBP_CPU_HOOK9_MBP3_GTL_QS_N")
	)
	(segment
		(start 83.664552 -179.669948)
		(end 73.36028 -179.669948)
		(width 0.127)
		(layer "In11.Cu")
		(net "DBP_CPU_HOOK9_MBP3_GTL_QS_N")
	)
	(segment
		(start 214.20328 -191.201548)
		(end 212.299804 -191.201548)
		(width 0.127)
		(layer "In13.Cu")
		(net "DBP_CPU_HOOK9_MBP3_GTL_QS_N")
	)
	(segment
		(start 222.703644 -187.406026)
		(end 222.703644 -189.438026)
		(width 0.127)
		(layer "In13.Cu")
		(net "DBP_CPU_HOOK9_MBP3_GTL_QS_N")
	)
	(segment
		(start 214.86368 -191.861948)
		(end 214.20328 -191.201548)
		(width 0.127)
		(layer "In13.Cu")
		(net "DBP_CPU_HOOK9_MBP3_GTL_QS_N")
	)
	(segment
		(start 262.589518 -186.700668)
		(end 261.696962 -185.808112)
		(width 0.127)
		(layer "In13.Cu")
		(net "DBP_CPU_HOOK9_MBP3_GTL_QS_N")
	)
	(segment
		(start 206.88808 -184.495948)
		(end 94.56928 -184.495948)
		(width 0.127)
		(layer "In13.Cu")
		(net "DBP_CPU_HOOK9_MBP3_GTL_QS_N")
	)
	(segment
		(start 94.56928 -184.495948)
		(end 90.238834 -180.165502)
		(width 0.127)
		(layer "In13.Cu")
		(net "DBP_CPU_HOOK9_MBP3_GTL_QS_N")
	)
	(segment
		(start 222.703644 -189.438026)
		(end 220.279722 -191.861948)
		(width 0.127)
		(layer "In13.Cu")
		(net "DBP_CPU_HOOK9_MBP3_GTL_QS_N")
	)
	(segment
		(start 262.589518 -186.845448)
		(end 262.589518 -186.700668)
		(width 0.127)
		(layer "In13.Cu")
		(net "DBP_CPU_HOOK9_MBP3_GTL_QS_N")
	)
	(segment
		(start 261.696962 -185.808112)
		(end 224.301558 -185.808112)
		(width 0.127)
		(layer "In13.Cu")
		(net "DBP_CPU_HOOK9_MBP3_GTL_QS_N")
	)
	(segment
		(start 220.279722 -191.861948)
		(end 214.86368 -191.861948)
		(width 0.127)
		(layer "In13.Cu")
		(net "DBP_CPU_HOOK9_MBP3_GTL_QS_N")
	)
	(segment
		(start 90.238834 -180.165502)
		(end 84.160106 -180.165502)
		(width 0.127)
		(layer "In13.Cu")
		(net "DBP_CPU_HOOK9_MBP3_GTL_QS_N")
	)
	(segment
		(start 212.299804 -191.201548)
		(end 209.83448 -188.736224)
		(width 0.127)
		(layer "In13.Cu")
		(net "DBP_CPU_HOOK9_MBP3_GTL_QS_N")
	)
	(segment
		(start 209.83448 -188.736224)
		(end 209.83448 -187.442348)
		(width 0.127)
		(layer "In13.Cu")
		(net "DBP_CPU_HOOK9_MBP3_GTL_QS_N")
	)
	(segment
		(start 209.83448 -187.442348)
		(end 206.88808 -184.495948)
		(width 0.127)
		(layer "In13.Cu")
		(net "DBP_CPU_HOOK9_MBP3_GTL_QS_N")
	)
	(segment
		(start 224.301558 -185.808112)
		(end 222.703644 -187.406026)
		(width 0.127)
		(layer "In13.Cu")
		(net "DBP_CPU_HOOK9_MBP3_GTL_QS_N")
	)
	(segment
		(start 206.743554 -153.024078)
		(end 206.030322 -153.73731)
		(width 0.12954)
		(layer "F.Cu")
		(net "DBP_CPU_HOOK8_MBP2_GTL_QS_N")
	)
	(segment
		(start 329.320906 -79.207868)
		(end 332.379574 -79.207868)
		(width 0.12954)
		(layer "F.Cu")
		(net "DBP_CPU_HOOK8_MBP2_GTL_QS_N")
	)
	(segment
		(start 332.379574 -79.207868)
		(end 333.327502 -78.25994)
		(width 0.12954)
		(layer "F.Cu")
		(net "DBP_CPU_HOOK8_MBP2_GTL_QS_N")
	)
	(segment
		(start 284.216856 -157.180788)
		(end 281.050238 -160.347406)
		(width 0.12954)
		(layer "F.Cu")
		(net "DBP_CPU_HOOK8_MBP2_GTL_QS_N")
	)
	(segment
		(start 267.868146 -154.981148)
		(end 257.89255 -154.981148)
		(width 0.12954)
		(layer "F.Cu")
		(net "DBP_CPU_HOOK8_MBP2_GTL_QS_N")
	)
	(segment
		(start 297.76674 -148.478748)
		(end 297.76674 -150.588726)
		(width 0.12954)
		(layer "F.Cu")
		(net "DBP_CPU_HOOK8_MBP2_GTL_QS_N")
	)
	(segment
		(start 328.545444 -78.432406)
		(end 329.320906 -79.207868)
		(width 0.12954)
		(layer "F.Cu")
		(net "DBP_CPU_HOOK8_MBP2_GTL_QS_N")
	)
	(segment
		(start 349.245174 -78.25994)
		(end 363.033818 -64.471296)
		(width 0.12954)
		(layer "F.Cu")
		(net "DBP_CPU_HOOK8_MBP2_GTL_QS_N")
	)
	(segment
		(start 297.76674 -150.588726)
		(end 296.171366 -152.1841)
		(width 0.12954)
		(layer "F.Cu")
		(net "DBP_CPU_HOOK8_MBP2_GTL_QS_N")
	)
	(segment
		(start 305.734974 -84.011008)
		(end 319.821814 -84.011008)
		(width 0.12954)
		(layer "F.Cu")
		(net "DBP_CPU_HOOK8_MBP2_GTL_QS_N")
	)
	(segment
		(start 325.400416 -78.432406)
		(end 328.545444 -78.432406)
		(width 0.12954)
		(layer "F.Cu")
		(net "DBP_CPU_HOOK8_MBP2_GTL_QS_N")
	)
	(segment
		(start 281.050238 -160.347406)
		(end 273.234404 -160.347406)
		(width 0.12954)
		(layer "F.Cu")
		(net "DBP_CPU_HOOK8_MBP2_GTL_QS_N")
	)
	(segment
		(start 255.93548 -153.024078)
		(end 206.743554 -153.024078)
		(width 0.12954)
		(layer "F.Cu")
		(net "DBP_CPU_HOOK8_MBP2_GTL_QS_N")
	)
	(segment
		(start 289.693858 -81.51241)
		(end 303.236376 -81.51241)
		(width 0.12954)
		(layer "F.Cu")
		(net "DBP_CPU_HOOK8_MBP2_GTL_QS_N")
	)
	(segment
		(start 333.327502 -78.25994)
		(end 349.245174 -78.25994)
		(width 0.12954)
		(layer "F.Cu")
		(net "DBP_CPU_HOOK8_MBP2_GTL_QS_N")
	)
	(segment
		(start 284.216856 -153.84272)
		(end 284.216856 -157.180788)
		(width 0.12954)
		(layer "F.Cu")
		(net "DBP_CPU_HOOK8_MBP2_GTL_QS_N")
	)
	(segment
		(start 319.821814 -84.011008)
		(end 325.400416 -78.432406)
		(width 0.12954)
		(layer "F.Cu")
		(net "DBP_CPU_HOOK8_MBP2_GTL_QS_N")
	)
	(segment
		(start 363.033818 -64.471296)
		(end 364.71352 -64.471296)
		(width 0.12954)
		(layer "F.Cu")
		(net "DBP_CPU_HOOK8_MBP2_GTL_QS_N")
	)
	(segment
		(start 257.89255 -154.981148)
		(end 255.93548 -153.024078)
		(width 0.12954)
		(layer "F.Cu")
		(net "DBP_CPU_HOOK8_MBP2_GTL_QS_N")
	)
	(segment
		(start 285.875476 -152.1841)
		(end 284.216856 -153.84272)
		(width 0.12954)
		(layer "F.Cu")
		(net "DBP_CPU_HOOK8_MBP2_GTL_QS_N")
	)
	(segment
		(start 285.853886 -77.672438)
		(end 289.693858 -81.51241)
		(width 0.12954)
		(layer "F.Cu")
		(net "DBP_CPU_HOOK8_MBP2_GTL_QS_N")
	)
	(segment
		(start 296.171366 -152.1841)
		(end 285.875476 -152.1841)
		(width 0.12954)
		(layer "F.Cu")
		(net "DBP_CPU_HOOK8_MBP2_GTL_QS_N")
	)
	(segment
		(start 273.234404 -160.347406)
		(end 267.868146 -154.981148)
		(width 0.12954)
		(layer "F.Cu")
		(net "DBP_CPU_HOOK8_MBP2_GTL_QS_N")
	)
	(segment
		(start 303.236376 -81.51241)
		(end 305.734974 -84.011008)
		(width 0.12954)
		(layer "F.Cu")
		(net "DBP_CPU_HOOK8_MBP2_GTL_QS_N")
	)
	(via
		(at 285.853886 -77.672438)
		(size 0.508)
		(drill 0.254)
		(layers "F.Cu" "B.Cu")
		(net "DBP_CPU_HOOK8_MBP2_GTL_QS_N")
	)
	(via
		(at 133.019546 -145.17243)
		(size 0.508)
		(drill 0.254)
		(layers "F.Cu" "B.Cu")
		(net "DBP_CPU_HOOK8_MBP2_GTL_QS_N")
	)
	(via
		(at 206.030322 -153.73731)
		(size 0.508)
		(drill 0.254)
		(layers "F.Cu" "B.Cu")
		(net "DBP_CPU_HOOK8_MBP2_GTL_QS_N")
	)
	(via
		(at 133.06806 -150.466298)
		(size 0.508)
		(drill 0.254)
		(layers "F.Cu" "B.Cu")
		(net "DBP_CPU_HOOK8_MBP2_GTL_QS_N")
	)
	(via
		(at 297.76674 -148.478748)
		(size 0.508)
		(drill 0.254)
		(layers "F.Cu" "B.Cu")
		(net "DBP_CPU_HOOK8_MBP2_GTL_QS_N")
	)
	(via
		(at 76.1746 -178.044348)
		(size 0.6604)
		(drill 0.3302)
		(layers "F.Cu" "B.Cu")
		(net "DBP_CPU_HOOK8_MBP2_GTL_QS_N")
	)
	(segment
		(start 73.58634 -179.02682)
		(end 73.639172 -178.852322)
		(width 0.12954)
		(layer "B.Cu")
		(net "DBP_CPU_HOOK8_MBP2_GTL_QS_N")
	)
	(segment
		(start 73.921112 -178.430428)
		(end 74.853038 -178.044348)
		(width 0.12954)
		(layer "B.Cu")
		(net "DBP_CPU_HOOK8_MBP2_GTL_QS_N")
	)
	(segment
		(start 70.369684 -182.903876)
		(end 70.392798 -182.92699)
		(width 0.12954)
		(layer "B.Cu")
		(net "DBP_CPU_HOOK8_MBP2_GTL_QS_N")
	)
	(segment
		(start 269.42288 -152.334976)
		(end 269.42288 -155.799028)
		(width 0.12954)
		(layer "B.Cu")
		(net "DBP_CPU_HOOK8_MBP2_GTL_QS_N")
	)
	(segment
		(start 312.91784 -165.100508)
		(end 320.17208 -172.354748)
		(width 0.12954)
		(layer "B.Cu")
		(net "DBP_CPU_HOOK8_MBP2_GTL_QS_N")
	)
	(segment
		(start 297.01236 -147.724368)
		(end 274.033488 -147.724368)
		(width 0.12954)
		(layer "B.Cu")
		(net "DBP_CPU_HOOK8_MBP2_GTL_QS_N")
	)
	(segment
		(start 274.033488 -147.724368)
		(end 269.42288 -152.334976)
		(width 0.12954)
		(layer "B.Cu")
		(net "DBP_CPU_HOOK8_MBP2_GTL_QS_N")
	)
	(segment
		(start 332.16088 -179.757832)
		(end 332.16088 -187.988702)
		(width 0.12954)
		(layer "B.Cu")
		(net "DBP_CPU_HOOK8_MBP2_GTL_QS_N")
	)
	(segment
		(start 324.757796 -172.354748)
		(end 332.16088 -179.757832)
		(width 0.12954)
		(layer "B.Cu")
		(net "DBP_CPU_HOOK8_MBP2_GTL_QS_N")
	)
	(segment
		(start 78.401672 -176.073816)
		(end 76.43114 -178.044348)
		(width 0.12954)
		(layer "B.Cu")
		(net "DBP_CPU_HOOK8_MBP2_GTL_QS_N")
	)
	(segment
		(start 73.639172 -178.852322)
		(end 73.921112 -178.430428)
		(width 0.12954)
		(layer "B.Cu")
		(net "DBP_CPU_HOOK8_MBP2_GTL_QS_N")
	)
	(segment
		(start 70.811644 -182.92699)
		(end 70.9168 -182.821834)
		(width 0.12954)
		(layer "B.Cu")
		(net "DBP_CPU_HOOK8_MBP2_GTL_QS_N")
	)
	(segment
		(start 320.17208 -172.354748)
		(end 324.757796 -172.354748)
		(width 0.12954)
		(layer "B.Cu")
		(net "DBP_CPU_HOOK8_MBP2_GTL_QS_N")
	)
	(segment
		(start 73.58634 -179.718208)
		(end 73.58634 -179.02682)
		(width 0.12954)
		(layer "B.Cu")
		(net "DBP_CPU_HOOK8_MBP2_GTL_QS_N")
	)
	(segment
		(start 331.540358 -188.609224)
		(end 331.540358 -190.42888)
		(width 0.12954)
		(layer "B.Cu")
		(net "DBP_CPU_HOOK8_MBP2_GTL_QS_N")
	)
	(segment
		(start 297.76674 -148.478748)
		(end 297.01236 -147.724368)
		(width 0.12954)
		(layer "B.Cu")
		(net "DBP_CPU_HOOK8_MBP2_GTL_QS_N")
	)
	(segment
		(start 278.72436 -165.100508)
		(end 312.91784 -165.100508)
		(width 0.12954)
		(layer "B.Cu")
		(net "DBP_CPU_HOOK8_MBP2_GTL_QS_N")
	)
	(segment
		(start 332.16088 -187.988702)
		(end 331.540358 -188.609224)
		(width 0.12954)
		(layer "B.Cu")
		(net "DBP_CPU_HOOK8_MBP2_GTL_QS_N")
	)
	(segment
		(start 133.019546 -145.17243)
		(end 132.667502 -144.820386)
		(width 0.12954)
		(layer "B.Cu")
		(net "DBP_CPU_HOOK8_MBP2_GTL_QS_N")
	)
	(segment
		(start 74.853038 -178.044348)
		(end 76.1746 -178.044348)
		(width 0.12954)
		(layer "B.Cu")
		(net "DBP_CPU_HOOK8_MBP2_GTL_QS_N")
	)
	(segment
		(start 70.9168 -182.821834)
		(end 70.9168 -182.387748)
		(width 0.12954)
		(layer "B.Cu")
		(net "DBP_CPU_HOOK8_MBP2_GTL_QS_N")
	)
	(segment
		(start 132.667502 -144.820386)
		(end 107.655106 -144.820386)
		(width 0.12954)
		(layer "B.Cu")
		(net "DBP_CPU_HOOK8_MBP2_GTL_QS_N")
	)
	(segment
		(start 107.655106 -144.820386)
		(end 78.401672 -174.07382)
		(width 0.12954)
		(layer "B.Cu")
		(net "DBP_CPU_HOOK8_MBP2_GTL_QS_N")
	)
	(segment
		(start 70.9168 -182.387748)
		(end 73.58634 -179.718208)
		(width 0.12954)
		(layer "B.Cu")
		(net "DBP_CPU_HOOK8_MBP2_GTL_QS_N")
	)
	(segment
		(start 78.401672 -174.07382)
		(end 78.401672 -176.073816)
		(width 0.12954)
		(layer "B.Cu")
		(net "DBP_CPU_HOOK8_MBP2_GTL_QS_N")
	)
	(segment
		(start 70.392798 -182.92699)
		(end 70.811644 -182.92699)
		(width 0.12954)
		(layer "B.Cu")
		(net "DBP_CPU_HOOK8_MBP2_GTL_QS_N")
	)
	(segment
		(start 69.353684 -182.903876)
		(end 70.369684 -182.903876)
		(width 0.12954)
		(layer "B.Cu")
		(net "DBP_CPU_HOOK8_MBP2_GTL_QS_N")
	)
	(segment
		(start 269.42288 -155.799028)
		(end 278.72436 -165.100508)
		(width 0.12954)
		(layer "B.Cu")
		(net "DBP_CPU_HOOK8_MBP2_GTL_QS_N")
	)
	(segment
		(start 76.43114 -178.044348)
		(end 76.1746 -178.044348)
		(width 0.12954)
		(layer "B.Cu")
		(net "DBP_CPU_HOOK8_MBP2_GTL_QS_N")
	)
	(segment
		(start 133.06806 -150.466298)
		(end 133.019546 -150.417784)
		(width 0.127)
		(layer "In2.Cu")
		(net "DBP_CPU_HOOK8_MBP2_GTL_QS_N")
	)
	(segment
		(start 297.76674 -148.478748)
		(end 297.76674 -145.960592)
		(width 0.127)
		(layer "In2.Cu")
		(net "DBP_CPU_HOOK8_MBP2_GTL_QS_N")
	)
	(segment
		(start 133.019546 -150.417784)
		(end 133.019546 -145.17243)
		(width 0.127)
		(layer "In2.Cu")
		(net "DBP_CPU_HOOK8_MBP2_GTL_QS_N")
	)
	(segment
		(start 285.853886 -134.047738)
		(end 285.853886 -77.672438)
		(width 0.127)
		(layer "In2.Cu")
		(net "DBP_CPU_HOOK8_MBP2_GTL_QS_N")
	)
	(segment
		(start 297.76674 -145.960592)
		(end 285.853886 -134.047738)
		(width 0.127)
		(layer "In2.Cu")
		(net "DBP_CPU_HOOK8_MBP2_GTL_QS_N")
	)
	(segment
		(start 180.979318 -149.577806)
		(end 141.064488 -149.577806)
		(width 0.127)
		(layer "In15.Cu")
		(net "DBP_CPU_HOOK8_MBP2_GTL_QS_N")
	)
	(segment
		(start 182.38978 -153.790396)
		(end 182.38978 -150.988268)
		(width 0.127)
		(layer "In15.Cu")
		(net "DBP_CPU_HOOK8_MBP2_GTL_QS_N")
	)
	(segment
		(start 182.38978 -150.988268)
		(end 180.979318 -149.577806)
		(width 0.127)
		(layer "In15.Cu")
		(net "DBP_CPU_HOOK8_MBP2_GTL_QS_N")
	)
	(segment
		(start 141.064488 -149.577806)
		(end 139.99845 -150.643844)
		(width 0.127)
		(layer "In15.Cu")
		(net "DBP_CPU_HOOK8_MBP2_GTL_QS_N")
	)
	(segment
		(start 206.030322 -155.197048)
		(end 202.947778 -158.279592)
		(width 0.127)
		(layer "In15.Cu")
		(net "DBP_CPU_HOOK8_MBP2_GTL_QS_N")
	)
	(segment
		(start 139.99845 -150.643844)
		(end 133.245606 -150.643844)
		(width 0.127)
		(layer "In15.Cu")
		(net "DBP_CPU_HOOK8_MBP2_GTL_QS_N")
	)
	(segment
		(start 202.947778 -158.279592)
		(end 197.950836 -158.279592)
		(width 0.127)
		(layer "In15.Cu")
		(net "DBP_CPU_HOOK8_MBP2_GTL_QS_N")
	)
	(segment
		(start 196.270626 -159.959802)
		(end 188.559186 -159.959802)
		(width 0.127)
		(layer "In15.Cu")
		(net "DBP_CPU_HOOK8_MBP2_GTL_QS_N")
	)
	(segment
		(start 188.559186 -159.959802)
		(end 182.38978 -153.790396)
		(width 0.127)
		(layer "In15.Cu")
		(net "DBP_CPU_HOOK8_MBP2_GTL_QS_N")
	)
	(segment
		(start 133.245606 -150.643844)
		(end 133.06806 -150.466298)
		(width 0.127)
		(layer "In15.Cu")
		(net "DBP_CPU_HOOK8_MBP2_GTL_QS_N")
	)
	(segment
		(start 206.030322 -153.73731)
		(end 206.030322 -155.197048)
		(width 0.127)
		(layer "In15.Cu")
		(net "DBP_CPU_HOOK8_MBP2_GTL_QS_N")
	)
	(segment
		(start 197.950836 -158.279592)
		(end 196.270626 -159.959802)
		(width 0.127)
		(layer "In15.Cu")
		(net "DBP_CPU_HOOK8_MBP2_GTL_QS_N")
	)
	(segment
		(start 109.290866 -233.342434)
		(end 109.290612 -233.34218)
		(width 0.12954)
		(layer "F.Cu")
		(net "DBP_CPU1_MBP1_GTL_R_N")
	)
	(segment
		(start 109.290866 -233.87812)
		(end 109.290866 -233.342434)
		(width 0.12954)
		(layer "F.Cu")
		(net "DBP_CPU1_MBP1_GTL_R_N")
	)
	(via
		(at 74.428858 -192.02019)
		(size 0.762)
		(drill 0.254)
		(layers "F.Cu" "B.Cu")
		(net "DBP_CPU1_MBP1_GTL_R_N")
	)
	(via
		(at 109.290612 -233.34218)
		(size 0.4572)
		(drill 0.2032)
		(layers "F.Cu" "B.Cu")
		(net "DBP_CPU1_MBP1_GTL_R_N")
	)
	(segment
		(start 74.428858 -192.02019)
		(end 74.428858 -191.186816)
		(width 0.12954)
		(layer "B.Cu")
		(net "DBP_CPU1_MBP1_GTL_R_N")
	)
	(segment
		(start 74.428858 -191.186816)
		(end 74.347324 -191.105282)
		(width 0.12954)
		(layer "B.Cu")
		(net "DBP_CPU1_MBP1_GTL_R_N")
	)
	(segment
		(start 105.784142 -232.847134)
		(end 105.569512 -232.632504)
		(width 0.0889)
		(layer "In4.Cu")
		(net "DBP_CPU1_MBP1_GTL_R_N")
	)
	(segment
		(start 105.994962 -232.93451)
		(end 105.784142 -232.847134)
		(width 0.0889)
		(layer "In4.Cu")
		(net "DBP_CPU1_MBP1_GTL_R_N")
	)
	(segment
		(start 89.459816 -224.404936)
		(end 89.459816 -224.379536)
		(width 0.0889)
		(layer "In4.Cu")
		(net "DBP_CPU1_MBP1_GTL_R_N")
	)
	(segment
		(start 102.982014 -228.154484)
		(end 102.71125 -228.04247)
		(width 0.0889)
		(layer "In4.Cu")
		(net "DBP_CPU1_MBP1_GTL_R_N")
	)
	(segment
		(start 86.654894 -219.159074)
		(end 85.889846 -218.014296)
		(width 0.0889)
		(layer "In4.Cu")
		(net "DBP_CPU1_MBP1_GTL_R_N")
	)
	(segment
		(start 108.163614 -233.017822)
		(end 108.148882 -233.026458)
		(width 0.0889)
		(layer "In4.Cu")
		(net "DBP_CPU1_MBP1_GTL_R_N")
	)
	(segment
		(start 74.69886 -193.377312)
		(end 74.428858 -192.02019)
		(width 0.127)
		(layer "In4.Cu")
		(net "DBP_CPU1_MBP1_GTL_R_N")
	)
	(segment
		(start 105.569512 -232.632504)
		(end 102.982014 -228.154484)
		(width 0.0889)
		(layer "In4.Cu")
		(net "DBP_CPU1_MBP1_GTL_R_N")
	)
	(segment
		(start 101.128068 -226.56927)
		(end 101.019864 -226.506786)
		(width 0.0889)
		(layer "In4.Cu")
		(net "DBP_CPU1_MBP1_GTL_R_N")
	)
	(segment
		(start 95.859854 -225.69805)
		(end 95.850964 -225.69297)
		(width 0.0889)
		(layer "In4.Cu")
		(net "DBP_CPU1_MBP1_GTL_R_N")
	)
	(segment
		(start 85.59927 -217.470482)
		(end 85.351112 -217.222324)
		(width 0.0889)
		(layer "In4.Cu")
		(net "DBP_CPU1_MBP1_GTL_R_N")
	)
	(segment
		(start 89.459816 -222.746062)
		(end 89.460578 -222.60941)
		(width 0.0889)
		(layer "In4.Cu")
		(net "DBP_CPU1_MBP1_GTL_R_N")
	)
	(segment
		(start 96.886014 -226.506786)
		(end 96.8756 -226.512882)
		(width 0.0889)
		(layer "In4.Cu")
		(net "DBP_CPU1_MBP1_GTL_R_N")
	)
	(segment
		(start 93.986096 -225.701606)
		(end 93.971364 -225.69297)
		(width 0.0889)
		(layer "In4.Cu")
		(net "DBP_CPU1_MBP1_GTL_R_N")
	)
	(segment
		(start 90.6907 -224.88398)
		(end 90.68181 -224.8789)
		(width 0.0889)
		(layer "In4.Cu")
		(net "DBP_CPU1_MBP1_GTL_R_N")
	)
	(segment
		(start 84.619338 -216.054178)
		(end 76.7334 -197.015608)
		(width 0.127)
		(layer "In4.Cu")
		(net "DBP_CPU1_MBP1_GTL_R_N")
	)
	(segment
		(start 96.038416 -226.027234)
		(end 96.038416 -226.017328)
		(width 0.0889)
		(layer "In4.Cu")
		(net "DBP_CPU1_MBP1_GTL_R_N")
	)
	(segment
		(start 89.459816 -222.780098)
		(end 89.459816 -222.746062)
		(width 0.0889)
		(layer "In4.Cu")
		(net "DBP_CPU1_MBP1_GTL_R_N")
	)
	(segment
		(start 108.935012 -233.24693)
		(end 108.53801 -233.017822)
		(width 0.0889)
		(layer "In4.Cu")
		(net "DBP_CPU1_MBP1_GTL_R_N")
	)
	(segment
		(start 88.599518 -221.05493)
		(end 88.425528 -220.88094)
		(width 0.0889)
		(layer "In4.Cu")
		(net "DBP_CPU1_MBP1_GTL_R_N")
	)
	(segment
		(start 85.889846 -218.014296)
		(end 85.771228 -217.727784)
		(width 0.0889)
		(layer "In4.Cu")
		(net "DBP_CPU1_MBP1_GTL_R_N")
	)
	(segment
		(start 88.21547 -220.71965)
		(end 86.654894 -219.159074)
		(width 0.0889)
		(layer "In4.Cu")
		(net "DBP_CPU1_MBP1_GTL_R_N")
	)
	(segment
		(start 97.825814 -226.506786)
		(end 97.811082 -226.515422)
		(width 0.0889)
		(layer "In4.Cu")
		(net "DBP_CPU1_MBP1_GTL_R_N")
	)
	(segment
		(start 85.771228 -217.727784)
		(end 85.59927 -217.470482)
		(width 0.0889)
		(layer "In4.Cu")
		(net "DBP_CPU1_MBP1_GTL_R_N")
	)
	(segment
		(start 75.346052 -194.939158)
		(end 74.69886 -193.377312)
		(width 0.127)
		(layer "In4.Cu")
		(net "DBP_CPU1_MBP1_GTL_R_N")
	)
	(segment
		(start 102.71125 -228.04247)
		(end 102.2604 -228.04247)
		(width 0.0889)
		(layer "In4.Cu")
		(net "DBP_CPU1_MBP1_GTL_R_N")
	)
	(segment
		(start 101.959918 -227.91801)
		(end 101.128068 -226.56927)
		(width 0.0889)
		(layer "In4.Cu")
		(net "DBP_CPU1_MBP1_GTL_R_N")
	)
	(segment
		(start 89.460578 -222.60941)
		(end 88.599518 -221.05493)
		(width 0.0889)
		(layer "In4.Cu")
		(net "DBP_CPU1_MBP1_GTL_R_N")
	)
	(segment
		(start 76.7334 -197.015608)
		(end 75.346052 -194.939158)
		(width 0.127)
		(layer "In4.Cu")
		(net "DBP_CPU1_MBP1_GTL_R_N")
	)
	(segment
		(start 107.223814 -233.017822)
		(end 107.209082 -233.026458)
		(width 0.0889)
		(layer "In4.Cu")
		(net "DBP_CPU1_MBP1_GTL_R_N")
	)
	(segment
		(start 93.046296 -225.701606)
		(end 93.031564 -225.69297)
		(width 0.0889)
		(layer "In4.Cu")
		(net "DBP_CPU1_MBP1_GTL_R_N")
	)
	(segment
		(start 98.765868 -226.506786)
		(end 98.755454 -226.512882)
		(width 0.0889)
		(layer "In4.Cu")
		(net "DBP_CPU1_MBP1_GTL_R_N")
	)
	(segment
		(start 90.307414 -224.8789)
		(end 90.292682 -224.887536)
		(width 0.0889)
		(layer "In4.Cu")
		(net "DBP_CPU1_MBP1_GTL_R_N")
	)
	(segment
		(start 91.162124 -225.699066)
		(end 91.15171 -225.69297)
		(width 0.0889)
		(layer "In4.Cu")
		(net "DBP_CPU1_MBP1_GTL_R_N")
	)
	(segment
		(start 85.351112 -217.222324)
		(end 84.619338 -216.054178)
		(width 0.127)
		(layer "In4.Cu")
		(net "DBP_CPU1_MBP1_GTL_R_N")
	)
	(segment
		(start 90.869262 -225.2218)
		(end 90.869262 -225.203258)
		(width 0.0889)
		(layer "In4.Cu")
		(net "DBP_CPU1_MBP1_GTL_R_N")
	)
	(segment
		(start 92.106496 -225.701606)
		(end 92.091764 -225.69297)
		(width 0.0889)
		(layer "In4.Cu")
		(net "DBP_CPU1_MBP1_GTL_R_N")
	)
	(segment
		(start 106.347768 -232.93451)
		(end 105.994962 -232.93451)
		(width 0.0889)
		(layer "In4.Cu")
		(net "DBP_CPU1_MBP1_GTL_R_N")
	)
	(segment
		(start 89.929462 -223.584262)
		(end 89.929462 -223.56699)
		(width 0.0889)
		(layer "In4.Cu")
		(net "DBP_CPU1_MBP1_GTL_R_N")
	)
	(segment
		(start 94.925896 -225.701606)
		(end 94.911164 -225.69297)
		(width 0.0889)
		(layer "In4.Cu")
		(net "DBP_CPU1_MBP1_GTL_R_N")
	)
	(arc
		(start 90.292682 -224.887536)
		(mid 90.016207 -224.954856)
		(end 89.74201 -224.8789)
		(width 0.0889)
		(layer "In4.Cu")
		(net "DBP_CPU1_MBP1_GTL_R_N")
	)
	(arc
		(start 97.26041 -226.506786)
		(mid 97.073212 -226.456643)
		(end 96.886014 -226.506786)
		(width 0.0889)
		(layer "In4.Cu")
		(net "DBP_CPU1_MBP1_GTL_R_N")
	)
	(arc
		(start 88.425528 -220.88094)
		(mid 88.381376 -220.842219)
		(end 88.332564 -220.809566)
		(width 0.0889)
		(layer "In4.Cu")
		(net "DBP_CPU1_MBP1_GTL_R_N")
	)
	(arc
		(start 97.811082 -226.515422)
		(mid 97.534607 -226.582742)
		(end 97.26041 -226.506786)
		(width 0.0889)
		(layer "In4.Cu")
		(net "DBP_CPU1_MBP1_GTL_R_N")
	)
	(arc
		(start 89.742264 -223.251268)
		(mid 89.539978 -223.052287)
		(end 89.459816 -222.780098)
		(width 0.0889)
		(layer "In4.Cu")
		(net "DBP_CPU1_MBP1_GTL_R_N")
	)
	(arc
		(start 107.209082 -233.026458)
		(mid 106.932607 -233.093778)
		(end 106.65841 -233.017822)
		(width 0.0889)
		(layer "In4.Cu")
		(net "DBP_CPU1_MBP1_GTL_R_N")
	)
	(arc
		(start 96.320864 -226.506786)
		(mid 96.116529 -226.304181)
		(end 96.038416 -226.027234)
		(width 0.0889)
		(layer "In4.Cu")
		(net "DBP_CPU1_MBP1_GTL_R_N")
	)
	(arc
		(start 90.68181 -224.8789)
		(mid 90.494612 -224.828757)
		(end 90.307414 -224.8789)
		(width 0.0889)
		(layer "In4.Cu")
		(net "DBP_CPU1_MBP1_GTL_R_N")
	)
	(arc
		(start 91.15171 -225.69297)
		(mid 90.949424 -225.493989)
		(end 90.869262 -225.2218)
		(width 0.0889)
		(layer "In4.Cu")
		(net "DBP_CPU1_MBP1_GTL_R_N")
	)
	(arc
		(start 89.929462 -223.56699)
		(mid 89.877192 -223.384625)
		(end 89.742264 -223.251268)
		(width 0.0889)
		(layer "In4.Cu")
		(net "DBP_CPU1_MBP1_GTL_R_N")
	)
	(arc
		(start 89.74201 -224.8789)
		(mid 89.539187 -224.678669)
		(end 89.459816 -224.404936)
		(width 0.0889)
		(layer "In4.Cu")
		(net "DBP_CPU1_MBP1_GTL_R_N")
	)
	(arc
		(start 93.596968 -225.69297)
		(mid 93.322739 -225.768895)
		(end 93.046296 -225.701606)
		(width 0.0889)
		(layer "In4.Cu")
		(net "DBP_CPU1_MBP1_GTL_R_N")
	)
	(arc
		(start 91.717368 -225.69297)
		(mid 91.440555 -225.768806)
		(end 91.162124 -225.699066)
		(width 0.0889)
		(layer "In4.Cu")
		(net "DBP_CPU1_MBP1_GTL_R_N")
	)
	(arc
		(start 99.140264 -226.506786)
		(mid 98.953066 -226.456643)
		(end 98.765868 -226.506786)
		(width 0.0889)
		(layer "In4.Cu")
		(net "DBP_CPU1_MBP1_GTL_R_N")
	)
	(arc
		(start 89.459816 -224.379536)
		(mid 89.537927 -224.102587)
		(end 89.742264 -223.899984)
		(width 0.0889)
		(layer "In4.Cu")
		(net "DBP_CPU1_MBP1_GTL_R_N")
	)
	(arc
		(start 102.2604 -228.04247)
		(mid 102.097782 -228.010123)
		(end 101.959918 -227.91801)
		(width 0.0889)
		(layer "In4.Cu")
		(net "DBP_CPU1_MBP1_GTL_R_N")
	)
	(arc
		(start 93.971364 -225.69297)
		(mid 93.784166 -225.642827)
		(end 93.596968 -225.69297)
		(width 0.0889)
		(layer "In4.Cu")
		(net "DBP_CPU1_MBP1_GTL_R_N")
	)
	(arc
		(start 89.742264 -223.899984)
		(mid 89.877197 -223.76663)
		(end 89.929462 -223.584262)
		(width 0.0889)
		(layer "In4.Cu")
		(net "DBP_CPU1_MBP1_GTL_R_N")
	)
	(arc
		(start 94.536768 -225.69297)
		(mid 94.262539 -225.768895)
		(end 93.986096 -225.701606)
		(width 0.0889)
		(layer "In4.Cu")
		(net "DBP_CPU1_MBP1_GTL_R_N")
	)
	(arc
		(start 95.850964 -225.69297)
		(mid 95.663766 -225.642827)
		(end 95.476568 -225.69297)
		(width 0.0889)
		(layer "In4.Cu")
		(net "DBP_CPU1_MBP1_GTL_R_N")
	)
	(arc
		(start 93.031564 -225.69297)
		(mid 92.844366 -225.642827)
		(end 92.657168 -225.69297)
		(width 0.0889)
		(layer "In4.Cu")
		(net "DBP_CPU1_MBP1_GTL_R_N")
	)
	(arc
		(start 88.332564 -220.809566)
		(mid 88.271069 -220.768447)
		(end 88.21547 -220.71965)
		(width 0.0889)
		(layer "In4.Cu")
		(net "DBP_CPU1_MBP1_GTL_R_N")
	)
	(arc
		(start 108.53801 -233.017822)
		(mid 108.350812 -232.967679)
		(end 108.163614 -233.017822)
		(width 0.0889)
		(layer "In4.Cu")
		(net "DBP_CPU1_MBP1_GTL_R_N")
	)
	(arc
		(start 94.911164 -225.69297)
		(mid 94.723966 -225.642827)
		(end 94.536768 -225.69297)
		(width 0.0889)
		(layer "In4.Cu")
		(net "DBP_CPU1_MBP1_GTL_R_N")
	)
	(arc
		(start 99.705668 -226.506786)
		(mid 99.422966 -226.582562)
		(end 99.140264 -226.506786)
		(width 0.0889)
		(layer "In4.Cu")
		(net "DBP_CPU1_MBP1_GTL_R_N")
	)
	(arc
		(start 98.20021 -226.506786)
		(mid 98.013012 -226.456643)
		(end 97.825814 -226.506786)
		(width 0.0889)
		(layer "In4.Cu")
		(net "DBP_CPU1_MBP1_GTL_R_N")
	)
	(arc
		(start 109.290612 -233.34218)
		(mid 109.106543 -233.317956)
		(end 108.935012 -233.24693)
		(width 0.0889)
		(layer "In4.Cu")
		(net "DBP_CPU1_MBP1_GTL_R_N")
	)
	(arc
		(start 92.657168 -225.69297)
		(mid 92.382939 -225.768895)
		(end 92.106496 -225.701606)
		(width 0.0889)
		(layer "In4.Cu")
		(net "DBP_CPU1_MBP1_GTL_R_N")
	)
	(arc
		(start 101.019864 -226.506786)
		(mid 100.832666 -226.456643)
		(end 100.645468 -226.506786)
		(width 0.0889)
		(layer "In4.Cu")
		(net "DBP_CPU1_MBP1_GTL_R_N")
	)
	(arc
		(start 90.869262 -225.203258)
		(mid 90.821583 -225.020358)
		(end 90.6907 -224.88398)
		(width 0.0889)
		(layer "In4.Cu")
		(net "DBP_CPU1_MBP1_GTL_R_N")
	)
	(arc
		(start 100.080064 -226.506786)
		(mid 99.892866 -226.456643)
		(end 99.705668 -226.506786)
		(width 0.0889)
		(layer "In4.Cu")
		(net "DBP_CPU1_MBP1_GTL_R_N")
	)
	(arc
		(start 100.645468 -226.506786)
		(mid 100.362766 -226.582562)
		(end 100.080064 -226.506786)
		(width 0.0889)
		(layer "In4.Cu")
		(net "DBP_CPU1_MBP1_GTL_R_N")
	)
	(arc
		(start 106.65841 -233.017822)
		(mid 106.508583 -232.955673)
		(end 106.347768 -232.93451)
		(width 0.0889)
		(layer "In4.Cu")
		(net "DBP_CPU1_MBP1_GTL_R_N")
	)
	(arc
		(start 96.038416 -226.017328)
		(mid 95.990737 -225.834428)
		(end 95.859854 -225.69805)
		(width 0.0889)
		(layer "In4.Cu")
		(net "DBP_CPU1_MBP1_GTL_R_N")
	)
	(arc
		(start 98.755454 -226.512882)
		(mid 98.477022 -226.582728)
		(end 98.20021 -226.506786)
		(width 0.0889)
		(layer "In4.Cu")
		(net "DBP_CPU1_MBP1_GTL_R_N")
	)
	(arc
		(start 92.091764 -225.69297)
		(mid 91.904566 -225.642827)
		(end 91.717368 -225.69297)
		(width 0.0889)
		(layer "In4.Cu")
		(net "DBP_CPU1_MBP1_GTL_R_N")
	)
	(arc
		(start 107.59821 -233.017822)
		(mid 107.411012 -232.967679)
		(end 107.223814 -233.017822)
		(width 0.0889)
		(layer "In4.Cu")
		(net "DBP_CPU1_MBP1_GTL_R_N")
	)
	(arc
		(start 95.476568 -225.69297)
		(mid 95.202339 -225.768895)
		(end 94.925896 -225.701606)
		(width 0.0889)
		(layer "In4.Cu")
		(net "DBP_CPU1_MBP1_GTL_R_N")
	)
	(arc
		(start 108.148882 -233.026458)
		(mid 107.872407 -233.093778)
		(end 107.59821 -233.017822)
		(width 0.0889)
		(layer "In4.Cu")
		(net "DBP_CPU1_MBP1_GTL_R_N")
	)
	(arc
		(start 96.8756 -226.512882)
		(mid 96.597422 -226.582605)
		(end 96.320864 -226.506786)
		(width 0.0889)
		(layer "In4.Cu")
		(net "DBP_CPU1_MBP1_GTL_R_N")
	)
	(segment
		(start 108.351066 -232.250488)
		(end 108.350812 -232.250234)
		(width 0.12954)
		(layer "F.Cu")
		(net "DBP_CPU1_MBP0_GTL_R_N")
	)
	(segment
		(start 108.350812 -232.250234)
		(end 108.350812 -231.714548)
		(width 0.12954)
		(layer "F.Cu")
		(net "DBP_CPU1_MBP0_GTL_R_N")
	)
	(via
		(at 108.350812 -231.714548)
		(size 0.4572)
		(drill 0.2032)
		(layers "F.Cu" "B.Cu")
		(net "DBP_CPU1_MBP0_GTL_R_N")
	)
	(via
		(at 80.763618 -196.05625)
		(size 0.508)
		(drill 0.254)
		(layers "F.Cu" "B.Cu")
		(net "DBP_CPU1_MBP0_GTL_R_N")
	)
	(segment
		(start 80.763618 -191.23406)
		(end 80.763618 -196.05625)
		(width 0.12954)
		(layer "B.Cu")
		(net "DBP_CPU1_MBP0_GTL_R_N")
	)
	(segment
		(start 92.66936 -222.34017)
		(end 92.433902 -222.34017)
		(width 0.0889)
		(layer "In4.Cu")
		(net "DBP_CPU1_MBP0_GTL_R_N")
	)
	(segment
		(start 88.340946 -215.931242)
		(end 88.332056 -215.926162)
		(width 0.0889)
		(layer "In4.Cu")
		(net "DBP_CPU1_MBP0_GTL_R_N")
	)
	(segment
		(start 102.429564 -224.065084)
		(end 102.417372 -224.057972)
		(width 0.0889)
		(layer "In4.Cu")
		(net "DBP_CPU1_MBP0_GTL_R_N")
	)
	(segment
		(start 88.989662 -218.692222)
		(end 88.989662 -218.683586)
		(width 0.0889)
		(layer "In4.Cu")
		(net "DBP_CPU1_MBP0_GTL_R_N")
	)
	(segment
		(start 95.865696 -222.445834)
		(end 95.850964 -222.437198)
		(width 0.0889)
		(layer "In4.Cu")
		(net "DBP_CPU1_MBP0_GTL_R_N")
	)
	(segment
		(start 90.226896 -219.190316)
		(end 90.212164 -219.18168)
		(width 0.0889)
		(layer "In4.Cu")
		(net "DBP_CPU1_MBP0_GTL_R_N")
	)
	(segment
		(start 105.630218 -227.28555)
		(end 105.215436 -227.28555)
		(width 0.0889)
		(layer "In4.Cu")
		(net "DBP_CPU1_MBP0_GTL_R_N")
	)
	(segment
		(start 104.966262 -226.831144)
		(end 104.966262 -226.822508)
		(width 0.0889)
		(layer "In4.Cu")
		(net "DBP_CPU1_MBP0_GTL_R_N")
	)
	(segment
		(start 102.9081 -224.88398)
		(end 102.89921 -224.8789)
		(width 0.0889)
		(layer "In4.Cu")
		(net "DBP_CPU1_MBP0_GTL_R_N")
	)
	(segment
		(start 97.825814 -223.251268)
		(end 97.8154 -223.257364)
		(width 0.0889)
		(layer "In4.Cu")
		(net "DBP_CPU1_MBP0_GTL_R_N")
	)
	(segment
		(start 88.520016 -217.888312)
		(end 88.520016 -217.878406)
		(width 0.0889)
		(layer "In4.Cu")
		(net "DBP_CPU1_MBP0_GTL_R_N")
	)
	(segment
		(start 87.219536 -215.062308)
		(end 86.989158 -214.83193)
		(width 0.0889)
		(layer "In4.Cu")
		(net "DBP_CPU1_MBP0_GTL_R_N")
	)
	(segment
		(start 93.046296 -222.445834)
		(end 93.031564 -222.437198)
		(width 0.0889)
		(layer "In4.Cu")
		(net "DBP_CPU1_MBP0_GTL_R_N")
	)
	(segment
		(start 108.255562 -231.12603)
		(end 108.255562 -230.79837)
		(width 0.0889)
		(layer "In4.Cu")
		(net "DBP_CPU1_MBP0_GTL_R_N")
	)
	(segment
		(start 100.645468 -223.251268)
		(end 100.635054 -223.257364)
		(width 0.0889)
		(layer "In4.Cu")
		(net "DBP_CPU1_MBP0_GTL_R_N")
	)
	(segment
		(start 88.332056 -216.574878)
		(end 88.340946 -216.569798)
		(width 0.0889)
		(layer "In4.Cu")
		(net "DBP_CPU1_MBP0_GTL_R_N")
	)
	(segment
		(start 102.438454 -224.070164)
		(end 102.429564 -224.065084)
		(width 0.0889)
		(layer "In4.Cu")
		(net "DBP_CPU1_MBP0_GTL_R_N")
	)
	(segment
		(start 93.986096 -222.445834)
		(end 93.971364 -222.437198)
		(width 0.0889)
		(layer "In4.Cu")
		(net "DBP_CPU1_MBP0_GTL_R_N")
	)
	(segment
		(start 88.341454 -217.559128)
		(end 88.332564 -217.554048)
		(width 0.0889)
		(layer "In4.Cu")
		(net "DBP_CPU1_MBP0_GTL_R_N")
	)
	(segment
		(start 86.783672 -214.626444)
		(end 82.308446 -203.822554)
		(width 0.127)
		(layer "In4.Cu")
		(net "DBP_CPU1_MBP0_GTL_R_N")
	)
	(segment
		(start 86.989158 -214.83193)
		(end 86.783672 -214.626444)
		(width 0.127)
		(layer "In4.Cu")
		(net "DBP_CPU1_MBP0_GTL_R_N")
	)
	(segment
		(start 87.675212 -215.062308)
		(end 87.219536 -215.062308)
		(width 0.0889)
		(layer "In4.Cu")
		(net "DBP_CPU1_MBP0_GTL_R_N")
	)
	(segment
		(start 91.339416 -221.149418)
		(end 91.339416 -221.115382)
		(width 0.0889)
		(layer "In4.Cu")
		(net "DBP_CPU1_MBP0_GTL_R_N")
	)
	(segment
		(start 98.765868 -223.251268)
		(end 98.755454 -223.257364)
		(width 0.0889)
		(layer "In4.Cu")
		(net "DBP_CPU1_MBP0_GTL_R_N")
	)
	(segment
		(start 91.339416 -219.515944)
		(end 91.339416 -219.506038)
		(width 0.0889)
		(layer "In4.Cu")
		(net "DBP_CPU1_MBP0_GTL_R_N")
	)
	(segment
		(start 102.617016 -224.404936)
		(end 102.617016 -224.389442)
		(width 0.0889)
		(layer "In4.Cu")
		(net "DBP_CPU1_MBP0_GTL_R_N")
	)
	(segment
		(start 91.6305 -221.628462)
		(end 91.62161 -221.623382)
		(width 0.0889)
		(layer "In4.Cu")
		(net "DBP_CPU1_MBP0_GTL_R_N")
	)
	(segment
		(start 88.049862 -217.07856)
		(end 88.049862 -217.048842)
		(width 0.0889)
		(layer "In4.Cu")
		(net "DBP_CPU1_MBP0_GTL_R_N")
	)
	(segment
		(start 101.9683 -223.256348)
		(end 101.95941 -223.251268)
		(width 0.0889)
		(layer "In4.Cu")
		(net "DBP_CPU1_MBP0_GTL_R_N")
	)
	(segment
		(start 101.585014 -223.251268)
		(end 101.5746 -223.257364)
		(width 0.0889)
		(layer "In4.Cu")
		(net "DBP_CPU1_MBP0_GTL_R_N")
	)
	(segment
		(start 104.496616 -226.027234)
		(end 104.496616 -226.017328)
		(width 0.0889)
		(layer "In4.Cu")
		(net "DBP_CPU1_MBP0_GTL_R_N")
	)
	(segment
		(start 105.881678 -227.18141)
		(end 105.630218 -227.28555)
		(width 0.0889)
		(layer "In4.Cu")
		(net "DBP_CPU1_MBP0_GTL_R_N")
	)
	(segment
		(start 108.255562 -230.79837)
		(end 106.277918 -227.28555)
		(width 0.0889)
		(layer "In4.Cu")
		(net "DBP_CPU1_MBP0_GTL_R_N")
	)
	(segment
		(start 108.350812 -231.714548)
		(end 108.255562 -231.12603)
		(width 0.0889)
		(layer "In4.Cu")
		(net "DBP_CPU1_MBP0_GTL_R_N")
	)
	(segment
		(start 99.705414 -223.251268)
		(end 99.695 -223.257364)
		(width 0.0889)
		(layer "In4.Cu")
		(net "DBP_CPU1_MBP0_GTL_R_N")
	)
	(segment
		(start 88.049862 -215.452198)
		(end 88.049862 -215.436704)
		(width 0.0889)
		(layer "In4.Cu")
		(net "DBP_CPU1_MBP0_GTL_R_N")
	)
	(segment
		(start 105.215436 -227.28555)
		(end 105.040176 -227.11029)
		(width 0.0889)
		(layer "In4.Cu")
		(net "DBP_CPU1_MBP0_GTL_R_N")
	)
	(segment
		(start 103.086662 -225.217482)
		(end 103.086662 -225.203258)
		(width 0.0889)
		(layer "In4.Cu")
		(net "DBP_CPU1_MBP0_GTL_R_N")
	)
	(segment
		(start 106.173778 -227.18141)
		(end 105.881678 -227.18141)
		(width 0.0889)
		(layer "In4.Cu")
		(net "DBP_CPU1_MBP0_GTL_R_N")
	)
	(segment
		(start 104.318054 -225.69805)
		(end 104.309164 -225.69297)
		(width 0.0889)
		(layer "In4.Cu")
		(net "DBP_CPU1_MBP0_GTL_R_N")
	)
	(segment
		(start 96.978216 -222.780098)
		(end 96.978216 -222.761556)
		(width 0.0889)
		(layer "In4.Cu")
		(net "DBP_CPU1_MBP0_GTL_R_N")
	)
	(segment
		(start 106.277918 -227.28555)
		(end 106.173778 -227.18141)
		(width 0.0889)
		(layer "In4.Cu")
		(net "DBP_CPU1_MBP0_GTL_R_N")
	)
	(segment
		(start 92.08008 -222.193612)
		(end 91.888818 -222.00235)
		(width 0.0889)
		(layer "In4.Cu")
		(net "DBP_CPU1_MBP0_GTL_R_N")
	)
	(segment
		(start 82.308446 -203.822554)
		(end 80.763618 -196.05625)
		(width 0.127)
		(layer "In4.Cu")
		(net "DBP_CPU1_MBP0_GTL_R_N")
	)
	(segment
		(start 87.8713 -215.117426)
		(end 87.86241 -215.112346)
		(width 0.0889)
		(layer "In4.Cu")
		(net "DBP_CPU1_MBP0_GTL_R_N")
	)
	(segment
		(start 103.384096 -225.701606)
		(end 103.369364 -225.69297)
		(width 0.0889)
		(layer "In4.Cu")
		(net "DBP_CPU1_MBP0_GTL_R_N")
	)
	(segment
		(start 94.925896 -222.445834)
		(end 94.911164 -222.437198)
		(width 0.0889)
		(layer "In4.Cu")
		(net "DBP_CPU1_MBP0_GTL_R_N")
	)
	(arc
		(start 90.212164 -219.18168)
		(mid 90.024966 -219.131537)
		(end 89.837768 -219.18168)
		(width 0.0889)
		(layer "In4.Cu")
		(net "DBP_CPU1_MBP0_GTL_R_N")
	)
	(arc
		(start 95.476568 -222.437198)
		(mid 95.202369 -222.513033)
		(end 94.925896 -222.445834)
		(width 0.0889)
		(layer "In4.Cu")
		(net "DBP_CPU1_MBP0_GTL_R_N")
	)
	(arc
		(start 102.417372 -224.057972)
		(mid 102.219144 -223.852124)
		(end 102.146862 -223.575626)
		(width 0.0889)
		(layer "In4.Cu")
		(net "DBP_CPU1_MBP0_GTL_R_N")
	)
	(arc
		(start 88.049862 -215.436704)
		(mid 88.002183 -215.253804)
		(end 87.8713 -215.117426)
		(width 0.0889)
		(layer "In4.Cu")
		(net "DBP_CPU1_MBP0_GTL_R_N")
	)
	(arc
		(start 97.8154 -223.257364)
		(mid 97.537222 -223.327056)
		(end 97.260664 -223.251268)
		(width 0.0889)
		(layer "In4.Cu")
		(net "DBP_CPU1_MBP0_GTL_R_N")
	)
	(arc
		(start 91.339416 -221.115382)
		(mid 91.419578 -220.843193)
		(end 91.621864 -220.644212)
		(width 0.0889)
		(layer "In4.Cu")
		(net "DBP_CPU1_MBP0_GTL_R_N")
	)
	(arc
		(start 89.837768 -219.18168)
		(mid 89.272269 -219.181919)
		(end 88.989662 -218.692222)
		(width 0.0889)
		(layer "In4.Cu")
		(net "DBP_CPU1_MBP0_GTL_R_N")
	)
	(arc
		(start 88.332564 -217.554048)
		(mid 88.129083 -217.353244)
		(end 88.049862 -217.07856)
		(width 0.0889)
		(layer "In4.Cu")
		(net "DBP_CPU1_MBP0_GTL_R_N")
	)
	(arc
		(start 96.416368 -222.437198)
		(mid 96.142169 -222.513033)
		(end 95.865696 -222.445834)
		(width 0.0889)
		(layer "In4.Cu")
		(net "DBP_CPU1_MBP0_GTL_R_N")
	)
	(arc
		(start 98.755454 -223.257364)
		(mid 98.477022 -223.327178)
		(end 98.20021 -223.251268)
		(width 0.0889)
		(layer "In4.Cu")
		(net "DBP_CPU1_MBP0_GTL_R_N")
	)
	(arc
		(start 92.433902 -222.34017)
		(mid 92.242415 -222.302081)
		(end 92.08008 -222.193612)
		(width 0.0889)
		(layer "In4.Cu")
		(net "DBP_CPU1_MBP0_GTL_R_N")
	)
	(arc
		(start 96.978216 -222.761556)
		(mid 96.790917 -222.437115)
		(end 96.416368 -222.437198)
		(width 0.0889)
		(layer "In4.Cu")
		(net "DBP_CPU1_MBP0_GTL_R_N")
	)
	(arc
		(start 95.850964 -222.437198)
		(mid 95.663766 -222.387055)
		(end 95.476568 -222.437198)
		(width 0.0889)
		(layer "In4.Cu")
		(net "DBP_CPU1_MBP0_GTL_R_N")
	)
	(arc
		(start 88.802464 -218.367864)
		(mid 88.598129 -218.165259)
		(end 88.520016 -217.888312)
		(width 0.0889)
		(layer "In4.Cu")
		(net "DBP_CPU1_MBP0_GTL_R_N")
	)
	(arc
		(start 100.635054 -223.257364)
		(mid 100.356622 -223.327178)
		(end 100.07981 -223.251268)
		(width 0.0889)
		(layer "In4.Cu")
		(net "DBP_CPU1_MBP0_GTL_R_N")
	)
	(arc
		(start 104.779064 -226.506786)
		(mid 104.574729 -226.304181)
		(end 104.496616 -226.027234)
		(width 0.0889)
		(layer "In4.Cu")
		(net "DBP_CPU1_MBP0_GTL_R_N")
	)
	(arc
		(start 90.777568 -219.18168)
		(mid 90.503369 -219.257515)
		(end 90.226896 -219.190316)
		(width 0.0889)
		(layer "In4.Cu")
		(net "DBP_CPU1_MBP0_GTL_R_N")
	)
	(arc
		(start 101.95941 -223.251268)
		(mid 101.772212 -223.201125)
		(end 101.585014 -223.251268)
		(width 0.0889)
		(layer "In4.Cu")
		(net "DBP_CPU1_MBP0_GTL_R_N")
	)
	(arc
		(start 104.966262 -226.822508)
		(mid 104.913992 -226.640143)
		(end 104.779064 -226.506786)
		(width 0.0889)
		(layer "In4.Cu")
		(net "DBP_CPU1_MBP0_GTL_R_N")
	)
	(arc
		(start 99.695 -223.257364)
		(mid 99.416822 -223.327056)
		(end 99.140264 -223.251268)
		(width 0.0889)
		(layer "In4.Cu")
		(net "DBP_CPU1_MBP0_GTL_R_N")
	)
	(arc
		(start 87.86241 -215.112346)
		(mid 87.772103 -215.075017)
		(end 87.675212 -215.062308)
		(width 0.0889)
		(layer "In4.Cu")
		(net "DBP_CPU1_MBP0_GTL_R_N")
	)
	(arc
		(start 97.260664 -223.251268)
		(mid 97.058378 -223.052287)
		(end 96.978216 -222.780098)
		(width 0.0889)
		(layer "In4.Cu")
		(net "DBP_CPU1_MBP0_GTL_R_N")
	)
	(arc
		(start 88.989662 -218.683586)
		(mid 88.937392 -218.501221)
		(end 88.802464 -218.367864)
		(width 0.0889)
		(layer "In4.Cu")
		(net "DBP_CPU1_MBP0_GTL_R_N")
	)
	(arc
		(start 104.496616 -226.017328)
		(mid 104.448937 -225.834428)
		(end 104.318054 -225.69805)
		(width 0.0889)
		(layer "In4.Cu")
		(net "DBP_CPU1_MBP0_GTL_R_N")
	)
	(arc
		(start 105.040176 -227.11029)
		(mid 104.985072 -226.975521)
		(end 104.966262 -226.831144)
		(width 0.0889)
		(layer "In4.Cu")
		(net "DBP_CPU1_MBP0_GTL_R_N")
	)
	(arc
		(start 91.794076 -221.84233)
		(mid 91.732139 -221.720218)
		(end 91.6305 -221.628462)
		(width 0.0889)
		(layer "In4.Cu")
		(net "DBP_CPU1_MBP0_GTL_R_N")
	)
	(arc
		(start 93.031564 -222.437198)
		(mid 92.856846 -222.364857)
		(end 92.66936 -222.34017)
		(width 0.0889)
		(layer "In4.Cu")
		(net "DBP_CPU1_MBP0_GTL_R_N")
	)
	(arc
		(start 91.621864 -219.995496)
		(mid 91.417529 -219.792891)
		(end 91.339416 -219.515944)
		(width 0.0889)
		(layer "In4.Cu")
		(net "DBP_CPU1_MBP0_GTL_R_N")
	)
	(arc
		(start 91.888818 -222.00235)
		(mid 91.831358 -221.928313)
		(end 91.794076 -221.84233)
		(width 0.0889)
		(layer "In4.Cu")
		(net "DBP_CPU1_MBP0_GTL_R_N")
	)
	(arc
		(start 93.971364 -222.437198)
		(mid 93.784166 -222.387055)
		(end 93.596968 -222.437198)
		(width 0.0889)
		(layer "In4.Cu")
		(net "DBP_CPU1_MBP0_GTL_R_N")
	)
	(arc
		(start 91.621864 -220.644212)
		(mid 91.809167 -220.319854)
		(end 91.621864 -219.995496)
		(width 0.0889)
		(layer "In4.Cu")
		(net "DBP_CPU1_MBP0_GTL_R_N")
	)
	(arc
		(start 102.89921 -224.8789)
		(mid 102.696387 -224.678669)
		(end 102.617016 -224.404936)
		(width 0.0889)
		(layer "In4.Cu")
		(net "DBP_CPU1_MBP0_GTL_R_N")
	)
	(arc
		(start 102.146862 -223.575626)
		(mid 102.099183 -223.392726)
		(end 101.9683 -223.256348)
		(width 0.0889)
		(layer "In4.Cu")
		(net "DBP_CPU1_MBP0_GTL_R_N")
	)
	(arc
		(start 94.536768 -222.437198)
		(mid 94.262569 -222.513033)
		(end 93.986096 -222.445834)
		(width 0.0889)
		(layer "In4.Cu")
		(net "DBP_CPU1_MBP0_GTL_R_N")
	)
	(arc
		(start 99.140264 -223.251268)
		(mid 98.953066 -223.201125)
		(end 98.765868 -223.251268)
		(width 0.0889)
		(layer "In4.Cu")
		(net "DBP_CPU1_MBP0_GTL_R_N")
	)
	(arc
		(start 91.62161 -221.623382)
		(mid 91.418787 -221.423151)
		(end 91.339416 -221.149418)
		(width 0.0889)
		(layer "In4.Cu")
		(net "DBP_CPU1_MBP0_GTL_R_N")
	)
	(arc
		(start 94.911164 -222.437198)
		(mid 94.723966 -222.387055)
		(end 94.536768 -222.437198)
		(width 0.0889)
		(layer "In4.Cu")
		(net "DBP_CPU1_MBP0_GTL_R_N")
	)
	(arc
		(start 103.086662 -225.203258)
		(mid 103.038983 -225.020358)
		(end 102.9081 -224.88398)
		(width 0.0889)
		(layer "In4.Cu")
		(net "DBP_CPU1_MBP0_GTL_R_N")
	)
	(arc
		(start 88.332056 -215.926162)
		(mid 88.129233 -215.725931)
		(end 88.049862 -215.452198)
		(width 0.0889)
		(layer "In4.Cu")
		(net "DBP_CPU1_MBP0_GTL_R_N")
	)
	(arc
		(start 102.617016 -224.389442)
		(mid 102.569337 -224.206542)
		(end 102.438454 -224.070164)
		(width 0.0889)
		(layer "In4.Cu")
		(net "DBP_CPU1_MBP0_GTL_R_N")
	)
	(arc
		(start 103.934768 -225.69297)
		(mid 103.660539 -225.768895)
		(end 103.384096 -225.701606)
		(width 0.0889)
		(layer "In4.Cu")
		(net "DBP_CPU1_MBP0_GTL_R_N")
	)
	(arc
		(start 88.340946 -216.569798)
		(mid 88.519543 -216.25052)
		(end 88.340946 -215.931242)
		(width 0.0889)
		(layer "In4.Cu")
		(net "DBP_CPU1_MBP0_GTL_R_N")
	)
	(arc
		(start 101.5746 -223.257364)
		(mid 101.296422 -223.327056)
		(end 101.019864 -223.251268)
		(width 0.0889)
		(layer "In4.Cu")
		(net "DBP_CPU1_MBP0_GTL_R_N")
	)
	(arc
		(start 88.049862 -217.048842)
		(mid 88.129232 -216.775108)
		(end 88.332056 -216.574878)
		(width 0.0889)
		(layer "In4.Cu")
		(net "DBP_CPU1_MBP0_GTL_R_N")
	)
	(arc
		(start 104.309164 -225.69297)
		(mid 104.121966 -225.642827)
		(end 103.934768 -225.69297)
		(width 0.0889)
		(layer "In4.Cu")
		(net "DBP_CPU1_MBP0_GTL_R_N")
	)
	(arc
		(start 88.520016 -217.878406)
		(mid 88.472337 -217.695506)
		(end 88.341454 -217.559128)
		(width 0.0889)
		(layer "In4.Cu")
		(net "DBP_CPU1_MBP0_GTL_R_N")
	)
	(arc
		(start 91.339416 -219.506038)
		(mid 91.152117 -219.181597)
		(end 90.777568 -219.18168)
		(width 0.0889)
		(layer "In4.Cu")
		(net "DBP_CPU1_MBP0_GTL_R_N")
	)
	(arc
		(start 100.07981 -223.251268)
		(mid 99.892612 -223.201125)
		(end 99.705414 -223.251268)
		(width 0.0889)
		(layer "In4.Cu")
		(net "DBP_CPU1_MBP0_GTL_R_N")
	)
	(arc
		(start 98.20021 -223.251268)
		(mid 98.013012 -223.201125)
		(end 97.825814 -223.251268)
		(width 0.0889)
		(layer "In4.Cu")
		(net "DBP_CPU1_MBP0_GTL_R_N")
	)
	(arc
		(start 101.019864 -223.251268)
		(mid 100.832666 -223.201125)
		(end 100.645468 -223.251268)
		(width 0.0889)
		(layer "In4.Cu")
		(net "DBP_CPU1_MBP0_GTL_R_N")
	)
	(arc
		(start 93.596968 -222.437198)
		(mid 93.322769 -222.513033)
		(end 93.046296 -222.445834)
		(width 0.0889)
		(layer "In4.Cu")
		(net "DBP_CPU1_MBP0_GTL_R_N")
	)
	(arc
		(start 103.369364 -225.69297)
		(mid 103.165883 -225.492166)
		(end 103.086662 -225.217482)
		(width 0.0889)
		(layer "In4.Cu")
		(net "DBP_CPU1_MBP0_GTL_R_N")
	)
	(segment
		(start 107.881166 -233.06405)
		(end 107.881166 -232.528364)
		(width 0.12954)
		(layer "F.Cu")
		(net "DBP_CPU1_HOOK9_MBP3_GTL_QS_R_N")
	)
	(segment
		(start 107.880912 -233.064304)
		(end 107.881166 -233.06405)
		(width 0.12954)
		(layer "F.Cu")
		(net "DBP_CPU1_HOOK9_MBP3_GTL_QS_R_N")
	)
	(via
		(at 70.369684 -186.802268)
		(size 0.762)
		(drill 0.254)
		(layers "F.Cu" "B.Cu")
		(net "DBP_CPU1_HOOK9_MBP3_GTL_QS_R_N")
	)
	(via
		(at 107.881166 -232.528364)
		(size 0.4572)
		(drill 0.2032)
		(layers "F.Cu" "B.Cu")
		(net "DBP_CPU1_HOOK9_MBP3_GTL_QS_R_N")
	)
	(segment
		(start 70.369684 -186.191906)
		(end 70.369684 -186.802268)
		(width 0.12954)
		(layer "B.Cu")
		(net "DBP_CPU1_HOOK9_MBP3_GTL_QS_R_N")
	)
	(segment
		(start 90.399616 -221.149418)
		(end 90.399616 -221.111826)
		(width 0.0889)
		(layer "In4.Cu")
		(net "DBP_CPU1_HOOK9_MBP3_GTL_QS_R_N")
	)
	(segment
		(start 90.68181 -220.644212)
		(end 90.6907 -220.639132)
		(width 0.0889)
		(layer "In4.Cu")
		(net "DBP_CPU1_HOOK9_MBP3_GTL_QS_R_N")
	)
	(segment
		(start 90.6907 -220.000576)
		(end 90.68181 -219.995496)
		(width 0.0889)
		(layer "In4.Cu")
		(net "DBP_CPU1_HOOK9_MBP3_GTL_QS_R_N")
	)
	(segment
		(start 90.6907 -221.628462)
		(end 90.68181 -221.623382)
		(width 0.0889)
		(layer "In4.Cu")
		(net "DBP_CPU1_HOOK9_MBP3_GTL_QS_R_N")
	)
	(segment
		(start 93.127068 -223.251268)
		(end 93.116654 -223.257364)
		(width 0.0889)
		(layer "In4.Cu")
		(net "DBP_CPU1_HOOK9_MBP3_GTL_QS_R_N")
	)
	(segment
		(start 91.160854 -222.442278)
		(end 91.151964 -222.437198)
		(width 0.0889)
		(layer "In4.Cu")
		(net "DBP_CPU1_HOOK9_MBP3_GTL_QS_R_N")
	)
	(segment
		(start 91.339416 -222.780098)
		(end 91.339416 -222.761556)
		(width 0.0889)
		(layer "In4.Cu")
		(net "DBP_CPU1_HOOK9_MBP3_GTL_QS_R_N")
	)
	(segment
		(start 103.464868 -226.506786)
		(end 103.454454 -226.512882)
		(width 0.0889)
		(layer "In4.Cu")
		(net "DBP_CPU1_HOOK9_MBP3_GTL_QS_R_N")
	)
	(segment
		(start 85.884258 -215.01227)
		(end 85.884258 -214.90813)
		(width 0.0889)
		(layer "In4.Cu")
		(net "DBP_CPU1_HOOK9_MBP3_GTL_QS_R_N")
	)
	(segment
		(start 94.066614 -223.251268)
		(end 94.0562 -223.257364)
		(width 0.0889)
		(layer "In4.Cu")
		(net "DBP_CPU1_HOOK9_MBP3_GTL_QS_R_N")
	)
	(segment
		(start 87.110062 -217.086434)
		(end 87.110062 -217.048842)
		(width 0.0889)
		(layer "In4.Cu")
		(net "DBP_CPU1_HOOK9_MBP3_GTL_QS_R_N")
	)
	(segment
		(start 95.946214 -223.251268)
		(end 95.9358 -223.257364)
		(width 0.0889)
		(layer "In4.Cu")
		(net "DBP_CPU1_HOOK9_MBP3_GTL_QS_R_N")
	)
	(segment
		(start 96.790764 -224.065084)
		(end 96.778572 -224.057972)
		(width 0.0889)
		(layer "In4.Cu")
		(net "DBP_CPU1_HOOK9_MBP3_GTL_QS_R_N")
	)
	(segment
		(start 101.504496 -225.701606)
		(end 101.489764 -225.69297)
		(width 0.0889)
		(layer "In4.Cu")
		(net "DBP_CPU1_HOOK9_MBP3_GTL_QS_R_N")
	)
	(segment
		(start 87.407242 -217.562684)
		(end 87.392256 -217.554048)
		(width 0.0889)
		(layer "In4.Cu")
		(net "DBP_CPU1_HOOK9_MBP3_GTL_QS_R_N")
	)
	(segment
		(start 107.484926 -232.36428)
		(end 106.991404 -231.870758)
		(width 0.0889)
		(layer "In4.Cu")
		(net "DBP_CPU1_HOOK9_MBP3_GTL_QS_R_N")
	)
	(segment
		(start 92.187014 -223.251268)
		(end 92.1766 -223.257364)
		(width 0.0889)
		(layer "In4.Cu")
		(net "DBP_CPU1_HOOK9_MBP3_GTL_QS_R_N")
	)
	(segment
		(start 103.848154 -226.511866)
		(end 103.839264 -226.506786)
		(width 0.0889)
		(layer "In4.Cu")
		(net "DBP_CPU1_HOOK9_MBP3_GTL_QS_R_N")
	)
	(segment
		(start 99.624896 -225.701606)
		(end 99.610164 -225.69297)
		(width 0.0889)
		(layer "In4.Cu")
		(net "DBP_CPU1_HOOK9_MBP3_GTL_QS_R_N")
	)
	(segment
		(start 97.2693 -224.88398)
		(end 97.26041 -224.8789)
		(width 0.0889)
		(layer "In4.Cu")
		(net "DBP_CPU1_HOOK9_MBP3_GTL_QS_R_N")
	)
	(segment
		(start 87.205058 -215.876124)
		(end 86.748112 -215.876124)
		(width 0.0889)
		(layer "In4.Cu")
		(net "DBP_CPU1_HOOK9_MBP3_GTL_QS_R_N")
	)
	(segment
		(start 88.520016 -219.515944)
		(end 88.520016 -219.506038)
		(width 0.0889)
		(layer "In4.Cu")
		(net "DBP_CPU1_HOOK9_MBP3_GTL_QS_R_N")
	)
	(segment
		(start 104.026716 -226.84105)
		(end 104.026716 -226.831144)
		(width 0.0889)
		(layer "In4.Cu")
		(net "DBP_CPU1_HOOK9_MBP3_GTL_QS_R_N")
	)
	(segment
		(start 95.006668 -223.251268)
		(end 94.996254 -223.257364)
		(width 0.0889)
		(layer "In4.Cu")
		(net "DBP_CPU1_HOOK9_MBP3_GTL_QS_R_N")
	)
	(segment
		(start 90.307414 -219.995496)
		(end 90.297 -220.001592)
		(width 0.0889)
		(layer "In4.Cu")
		(net "DBP_CPU1_HOOK9_MBP3_GTL_QS_R_N")
	)
	(segment
		(start 86.748112 -215.876124)
		(end 85.884258 -215.01227)
		(width 0.0889)
		(layer "In4.Cu")
		(net "DBP_CPU1_HOOK9_MBP3_GTL_QS_R_N")
	)
	(segment
		(start 104.496616 -227.667058)
		(end 104.496616 -227.64496)
		(width 0.0889)
		(layer "In4.Cu")
		(net "DBP_CPU1_HOOK9_MBP3_GTL_QS_R_N")
	)
	(segment
		(start 73.0504 -186.070748)
		(end 72.280018 -186.84113)
		(width 0.127)
		(layer "In4.Cu")
		(net "DBP_CPU1_HOOK9_MBP3_GTL_QS_R_N")
	)
	(segment
		(start 96.978216 -224.404936)
		(end 96.978216 -224.389442)
		(width 0.0889)
		(layer "In4.Cu")
		(net "DBP_CPU1_HOOK9_MBP3_GTL_QS_R_N")
	)
	(segment
		(start 97.447862 -225.217482)
		(end 97.447862 -225.203258)
		(width 0.0889)
		(layer "In4.Cu")
		(net "DBP_CPU1_HOOK9_MBP3_GTL_QS_R_N")
	)
	(segment
		(start 98.685096 -225.701606)
		(end 98.670364 -225.69297)
		(width 0.0889)
		(layer "In4.Cu")
		(net "DBP_CPU1_HOOK9_MBP3_GTL_QS_R_N")
	)
	(segment
		(start 106.991404 -231.870758)
		(end 105.2703 -228.813614)
		(width 0.0889)
		(layer "In4.Cu")
		(net "DBP_CPU1_HOOK9_MBP3_GTL_QS_R_N")
	)
	(segment
		(start 72.280018 -186.84113)
		(end 70.388226 -186.84113)
		(width 0.127)
		(layer "In4.Cu")
		(net "DBP_CPU1_HOOK9_MBP3_GTL_QS_R_N")
	)
	(segment
		(start 76.181458 -191.483488)
		(end 76.181458 -188.72073)
		(width 0.127)
		(layer "In4.Cu")
		(net "DBP_CPU1_HOOK9_MBP3_GTL_QS_R_N")
	)
	(segment
		(start 96.3295 -223.256348)
		(end 96.32061 -223.251268)
		(width 0.0889)
		(layer "In4.Cu")
		(net "DBP_CPU1_HOOK9_MBP3_GTL_QS_R_N")
	)
	(segment
		(start 70.388226 -186.84113)
		(end 70.369684 -186.822588)
		(width 0.127)
		(layer "In4.Cu")
		(net "DBP_CPU1_HOOK9_MBP3_GTL_QS_R_N")
	)
	(segment
		(start 87.401146 -215.931242)
		(end 87.392256 -215.926162)
		(width 0.0889)
		(layer "In4.Cu")
		(net "DBP_CPU1_HOOK9_MBP3_GTL_QS_R_N")
	)
	(segment
		(start 107.881166 -232.528364)
		(end 107.484926 -232.36428)
		(width 0.0889)
		(layer "In4.Cu")
		(net "DBP_CPU1_HOOK9_MBP3_GTL_QS_R_N")
	)
	(segment
		(start 100.564696 -225.701606)
		(end 100.549964 -225.69297)
		(width 0.0889)
		(layer "In4.Cu")
		(net "DBP_CPU1_HOOK9_MBP3_GTL_QS_R_N")
	)
	(segment
		(start 102.617016 -226.032822)
		(end 102.617016 -226.017328)
		(width 0.0889)
		(layer "In4.Cu")
		(net "DBP_CPU1_HOOK9_MBP3_GTL_QS_R_N")
	)
	(segment
		(start 91.151964 -222.437198)
		(end 91.145868 -222.433642)
		(width 0.0889)
		(layer "In4.Cu")
		(net "DBP_CPU1_HOOK9_MBP3_GTL_QS_R_N")
	)
	(segment
		(start 97.745296 -225.701606)
		(end 97.730564 -225.69297)
		(width 0.0889)
		(layer "In4.Cu")
		(net "DBP_CPU1_HOOK9_MBP3_GTL_QS_R_N")
	)
	(segment
		(start 105.2703 -228.813614)
		(end 105.165144 -228.708204)
		(width 0.0889)
		(layer "In4.Cu")
		(net "DBP_CPU1_HOOK9_MBP3_GTL_QS_R_N")
	)
	(segment
		(start 88.341454 -219.18676)
		(end 88.300306 -219.163138)
		(width 0.0889)
		(layer "In4.Cu")
		(net "DBP_CPU1_HOOK9_MBP3_GTL_QS_R_N")
	)
	(segment
		(start 102.438454 -225.69805)
		(end 102.429564 -225.69297)
		(width 0.0889)
		(layer "In4.Cu")
		(net "DBP_CPU1_HOOK9_MBP3_GTL_QS_R_N")
	)
	(segment
		(start 70.369684 -186.822588)
		(end 70.369684 -186.802268)
		(width 0.127)
		(layer "In4.Cu")
		(net "DBP_CPU1_HOOK9_MBP3_GTL_QS_R_N")
	)
	(segment
		(start 85.884258 -214.90813)
		(end 76.181458 -191.483488)
		(width 0.127)
		(layer "In4.Cu")
		(net "DBP_CPU1_HOOK9_MBP3_GTL_QS_R_N")
	)
	(segment
		(start 76.181458 -188.72073)
		(end 73.531476 -186.070748)
		(width 0.127)
		(layer "In4.Cu")
		(net "DBP_CPU1_HOOK9_MBP3_GTL_QS_R_N")
	)
	(segment
		(start 88.106758 -219.11183)
		(end 87.769446 -219.11183)
		(width 0.0889)
		(layer "In4.Cu")
		(net "DBP_CPU1_HOOK9_MBP3_GTL_QS_R_N")
	)
	(segment
		(start 96.799654 -224.070164)
		(end 96.790764 -224.065084)
		(width 0.0889)
		(layer "In4.Cu")
		(net "DBP_CPU1_HOOK9_MBP3_GTL_QS_R_N")
	)
	(segment
		(start 104.913684 -228.21265)
		(end 104.77881 -228.134672)
		(width 0.0889)
		(layer "In4.Cu")
		(net "DBP_CPU1_HOOK9_MBP3_GTL_QS_R_N")
	)
	(segment
		(start 104.318054 -227.325682)
		(end 104.309164 -227.320602)
		(width 0.0889)
		(layer "In4.Cu")
		(net "DBP_CPU1_HOOK9_MBP3_GTL_QS_R_N")
	)
	(segment
		(start 87.392256 -216.574878)
		(end 87.401146 -216.569798)
		(width 0.0889)
		(layer "In4.Cu")
		(net "DBP_CPU1_HOOK9_MBP3_GTL_QS_R_N")
	)
	(segment
		(start 73.531476 -186.070748)
		(end 73.0504 -186.070748)
		(width 0.127)
		(layer "In4.Cu")
		(net "DBP_CPU1_HOOK9_MBP3_GTL_QS_R_N")
	)
	(arc
		(start 87.769446 -219.11183)
		(mid 87.724792 -219.109803)
		(end 87.680546 -219.103448)
		(width 0.0889)
		(layer "In4.Cu")
		(net "DBP_CPU1_HOOK9_MBP3_GTL_QS_R_N")
	)
	(arc
		(start 96.508062 -223.575626)
		(mid 96.460383 -223.392726)
		(end 96.3295 -223.256348)
		(width 0.0889)
		(layer "In4.Cu")
		(net "DBP_CPU1_HOOK9_MBP3_GTL_QS_R_N")
	)
	(arc
		(start 95.9358 -223.257364)
		(mid 95.657622 -223.327056)
		(end 95.381064 -223.251268)
		(width 0.0889)
		(layer "In4.Cu")
		(net "DBP_CPU1_HOOK9_MBP3_GTL_QS_R_N")
	)
	(arc
		(start 99.610164 -225.69297)
		(mid 99.422966 -225.642827)
		(end 99.235768 -225.69297)
		(width 0.0889)
		(layer "In4.Cu")
		(net "DBP_CPU1_HOOK9_MBP3_GTL_QS_R_N")
	)
	(arc
		(start 101.115368 -225.69297)
		(mid 100.841139 -225.768895)
		(end 100.564696 -225.701606)
		(width 0.0889)
		(layer "In4.Cu")
		(net "DBP_CPU1_HOOK9_MBP3_GTL_QS_R_N")
	)
	(arc
		(start 87.680546 -219.103448)
		(mid 87.517838 -219.050434)
		(end 87.372444 -218.960192)
		(width 0.0889)
		(layer "In4.Cu")
		(net "DBP_CPU1_HOOK9_MBP3_GTL_QS_R_N")
	)
	(arc
		(start 87.372444 -218.960192)
		(mid 87.32119 -218.886893)
		(end 87.298276 -218.800426)
		(width 0.0889)
		(layer "In4.Cu")
		(net "DBP_CPU1_HOOK9_MBP3_GTL_QS_R_N")
	)
	(arc
		(start 91.339416 -222.761556)
		(mid 91.291737 -222.578656)
		(end 91.160854 -222.442278)
		(width 0.0889)
		(layer "In4.Cu")
		(net "DBP_CPU1_HOOK9_MBP3_GTL_QS_R_N")
	)
	(arc
		(start 97.26041 -224.8789)
		(mid 97.057587 -224.678669)
		(end 96.978216 -224.404936)
		(width 0.0889)
		(layer "In4.Cu")
		(net "DBP_CPU1_HOOK9_MBP3_GTL_QS_R_N")
	)
	(arc
		(start 90.68181 -219.995496)
		(mid 90.494612 -219.945353)
		(end 90.307414 -219.995496)
		(width 0.0889)
		(layer "In4.Cu")
		(net "DBP_CPU1_HOOK9_MBP3_GTL_QS_R_N")
	)
	(arc
		(start 100.175568 -225.69297)
		(mid 99.901339 -225.768895)
		(end 99.624896 -225.701606)
		(width 0.0889)
		(layer "In4.Cu")
		(net "DBP_CPU1_HOOK9_MBP3_GTL_QS_R_N")
	)
	(arc
		(start 104.496616 -227.64496)
		(mid 104.448937 -227.46206)
		(end 104.318054 -227.325682)
		(width 0.0889)
		(layer "In4.Cu")
		(net "DBP_CPU1_HOOK9_MBP3_GTL_QS_R_N")
	)
	(arc
		(start 98.670364 -225.69297)
		(mid 98.483166 -225.642827)
		(end 98.295968 -225.69297)
		(width 0.0889)
		(layer "In4.Cu")
		(net "DBP_CPU1_HOOK9_MBP3_GTL_QS_R_N")
	)
	(arc
		(start 100.549964 -225.69297)
		(mid 100.362766 -225.642827)
		(end 100.175568 -225.69297)
		(width 0.0889)
		(layer "In4.Cu")
		(net "DBP_CPU1_HOOK9_MBP3_GTL_QS_R_N")
	)
	(arc
		(start 87.445342 -218.20378)
		(mid 87.545007 -218.054482)
		(end 87.579962 -217.878406)
		(width 0.0889)
		(layer "In4.Cu")
		(net "DBP_CPU1_HOOK9_MBP3_GTL_QS_R_N")
	)
	(arc
		(start 88.802464 -219.995496)
		(mid 88.598129 -219.792891)
		(end 88.520016 -219.515944)
		(width 0.0889)
		(layer "In4.Cu")
		(net "DBP_CPU1_HOOK9_MBP3_GTL_QS_R_N")
	)
	(arc
		(start 87.298276 -218.800426)
		(mid 87.322974 -218.490068)
		(end 87.445342 -218.20378)
		(width 0.0889)
		(layer "In4.Cu")
		(net "DBP_CPU1_HOOK9_MBP3_GTL_QS_R_N")
	)
	(arc
		(start 88.520016 -219.506038)
		(mid 88.472337 -219.323138)
		(end 88.341454 -219.18676)
		(width 0.0889)
		(layer "In4.Cu")
		(net "DBP_CPU1_HOOK9_MBP3_GTL_QS_R_N")
	)
	(arc
		(start 99.235768 -225.69297)
		(mid 98.961539 -225.768895)
		(end 98.685096 -225.701606)
		(width 0.0889)
		(layer "In4.Cu")
		(net "DBP_CPU1_HOOK9_MBP3_GTL_QS_R_N")
	)
	(arc
		(start 94.44101 -223.251268)
		(mid 94.253812 -223.201125)
		(end 94.066614 -223.251268)
		(width 0.0889)
		(layer "In4.Cu")
		(net "DBP_CPU1_HOOK9_MBP3_GTL_QS_R_N")
	)
	(arc
		(start 105.076498 -228.49459)
		(mid 105.03288 -228.331789)
		(end 104.913684 -228.21265)
		(width 0.0889)
		(layer "In4.Cu")
		(net "DBP_CPU1_HOOK9_MBP3_GTL_QS_R_N")
	)
	(arc
		(start 97.730564 -225.69297)
		(mid 97.527083 -225.492166)
		(end 97.447862 -225.217482)
		(width 0.0889)
		(layer "In4.Cu")
		(net "DBP_CPU1_HOOK9_MBP3_GTL_QS_R_N")
	)
	(arc
		(start 90.869262 -221.94774)
		(mid 90.821583 -221.76484)
		(end 90.6907 -221.628462)
		(width 0.0889)
		(layer "In4.Cu")
		(net "DBP_CPU1_HOOK9_MBP3_GTL_QS_R_N")
	)
	(arc
		(start 102.617016 -226.017328)
		(mid 102.569337 -225.834428)
		(end 102.438454 -225.69805)
		(width 0.0889)
		(layer "In4.Cu")
		(net "DBP_CPU1_HOOK9_MBP3_GTL_QS_R_N")
	)
	(arc
		(start 87.110062 -217.048842)
		(mid 87.189432 -216.775108)
		(end 87.392256 -216.574878)
		(width 0.0889)
		(layer "In4.Cu")
		(net "DBP_CPU1_HOOK9_MBP3_GTL_QS_R_N")
	)
	(arc
		(start 101.489764 -225.69297)
		(mid 101.302566 -225.642827)
		(end 101.115368 -225.69297)
		(width 0.0889)
		(layer "In4.Cu")
		(net "DBP_CPU1_HOOK9_MBP3_GTL_QS_R_N")
	)
	(arc
		(start 94.996254 -223.257364)
		(mid 94.717822 -223.327178)
		(end 94.44101 -223.251268)
		(width 0.0889)
		(layer "In4.Cu")
		(net "DBP_CPU1_HOOK9_MBP3_GTL_QS_R_N")
	)
	(arc
		(start 88.300306 -219.163138)
		(mid 88.206881 -219.124856)
		(end 88.106758 -219.11183)
		(width 0.0889)
		(layer "In4.Cu")
		(net "DBP_CPU1_HOOK9_MBP3_GTL_QS_R_N")
	)
	(arc
		(start 96.978216 -224.389442)
		(mid 96.930537 -224.206542)
		(end 96.799654 -224.070164)
		(width 0.0889)
		(layer "In4.Cu")
		(net "DBP_CPU1_HOOK9_MBP3_GTL_QS_R_N")
	)
	(arc
		(start 104.77881 -228.134672)
		(mid 104.577528 -227.937185)
		(end 104.496616 -227.667058)
		(width 0.0889)
		(layer "In4.Cu")
		(net "DBP_CPU1_HOOK9_MBP3_GTL_QS_R_N")
	)
	(arc
		(start 102.055168 -225.69297)
		(mid 101.780939 -225.768895)
		(end 101.504496 -225.701606)
		(width 0.0889)
		(layer "In4.Cu")
		(net "DBP_CPU1_HOOK9_MBP3_GTL_QS_R_N")
	)
	(arc
		(start 90.297 -220.001592)
		(mid 90.018822 -220.071315)
		(end 89.742264 -219.995496)
		(width 0.0889)
		(layer "In4.Cu")
		(net "DBP_CPU1_HOOK9_MBP3_GTL_QS_R_N")
	)
	(arc
		(start 105.165144 -228.708204)
		(mid 105.099575 -228.610212)
		(end 105.076498 -228.49459)
		(width 0.0889)
		(layer "In4.Cu")
		(net "DBP_CPU1_HOOK9_MBP3_GTL_QS_R_N")
	)
	(arc
		(start 104.309164 -227.320602)
		(mid 104.104829 -227.117997)
		(end 104.026716 -226.84105)
		(width 0.0889)
		(layer "In4.Cu")
		(net "DBP_CPU1_HOOK9_MBP3_GTL_QS_R_N")
	)
	(arc
		(start 102.89921 -226.506786)
		(mid 102.696387 -226.306555)
		(end 102.617016 -226.032822)
		(width 0.0889)
		(layer "In4.Cu")
		(net "DBP_CPU1_HOOK9_MBP3_GTL_QS_R_N")
	)
	(arc
		(start 104.026716 -226.831144)
		(mid 103.979037 -226.648244)
		(end 103.848154 -226.511866)
		(width 0.0889)
		(layer "In4.Cu")
		(net "DBP_CPU1_HOOK9_MBP3_GTL_QS_R_N")
	)
	(arc
		(start 87.579962 -217.878406)
		(mid 87.533958 -217.698469)
		(end 87.407242 -217.562684)
		(width 0.0889)
		(layer "In4.Cu")
		(net "DBP_CPU1_HOOK9_MBP3_GTL_QS_R_N")
	)
	(arc
		(start 98.295968 -225.69297)
		(mid 98.021739 -225.768895)
		(end 97.745296 -225.701606)
		(width 0.0889)
		(layer "In4.Cu")
		(net "DBP_CPU1_HOOK9_MBP3_GTL_QS_R_N")
	)
	(arc
		(start 92.56141 -223.251268)
		(mid 92.374212 -223.201125)
		(end 92.187014 -223.251268)
		(width 0.0889)
		(layer "In4.Cu")
		(net "DBP_CPU1_HOOK9_MBP3_GTL_QS_R_N")
	)
	(arc
		(start 94.0562 -223.257364)
		(mid 93.778022 -223.327056)
		(end 93.501464 -223.251268)
		(width 0.0889)
		(layer "In4.Cu")
		(net "DBP_CPU1_HOOK9_MBP3_GTL_QS_R_N")
	)
	(arc
		(start 91.621864 -223.251268)
		(mid 91.419578 -223.052287)
		(end 91.339416 -222.780098)
		(width 0.0889)
		(layer "In4.Cu")
		(net "DBP_CPU1_HOOK9_MBP3_GTL_QS_R_N")
	)
	(arc
		(start 89.367868 -219.995496)
		(mid 89.085166 -220.071272)
		(end 88.802464 -219.995496)
		(width 0.0889)
		(layer "In4.Cu")
		(net "DBP_CPU1_HOOK9_MBP3_GTL_QS_R_N")
	)
	(arc
		(start 90.68181 -221.623382)
		(mid 90.478987 -221.423151)
		(end 90.399616 -221.149418)
		(width 0.0889)
		(layer "In4.Cu")
		(net "DBP_CPU1_HOOK9_MBP3_GTL_QS_R_N")
	)
	(arc
		(start 95.381064 -223.251268)
		(mid 95.193866 -223.201125)
		(end 95.006668 -223.251268)
		(width 0.0889)
		(layer "In4.Cu")
		(net "DBP_CPU1_HOOK9_MBP3_GTL_QS_R_N")
	)
	(arc
		(start 91.145868 -222.433642)
		(mid 90.943281 -222.227291)
		(end 90.869262 -221.94774)
		(width 0.0889)
		(layer "In4.Cu")
		(net "DBP_CPU1_HOOK9_MBP3_GTL_QS_R_N")
	)
	(arc
		(start 97.447862 -225.203258)
		(mid 97.400183 -225.020358)
		(end 97.2693 -224.88398)
		(width 0.0889)
		(layer "In4.Cu")
		(net "DBP_CPU1_HOOK9_MBP3_GTL_QS_R_N")
	)
	(arc
		(start 92.1766 -223.257364)
		(mid 91.898422 -223.327056)
		(end 91.621864 -223.251268)
		(width 0.0889)
		(layer "In4.Cu")
		(net "DBP_CPU1_HOOK9_MBP3_GTL_QS_R_N")
	)
	(arc
		(start 87.401146 -216.569798)
		(mid 87.579743 -216.25052)
		(end 87.401146 -215.931242)
		(width 0.0889)
		(layer "In4.Cu")
		(net "DBP_CPU1_HOOK9_MBP3_GTL_QS_R_N")
	)
	(arc
		(start 87.392256 -215.926162)
		(mid 87.301949 -215.888833)
		(end 87.205058 -215.876124)
		(width 0.0889)
		(layer "In4.Cu")
		(net "DBP_CPU1_HOOK9_MBP3_GTL_QS_R_N")
	)
	(arc
		(start 87.392256 -217.554048)
		(mid 87.190974 -217.356561)
		(end 87.110062 -217.086434)
		(width 0.0889)
		(layer "In4.Cu")
		(net "DBP_CPU1_HOOK9_MBP3_GTL_QS_R_N")
	)
	(arc
		(start 96.32061 -223.251268)
		(mid 96.133412 -223.201125)
		(end 95.946214 -223.251268)
		(width 0.0889)
		(layer "In4.Cu")
		(net "DBP_CPU1_HOOK9_MBP3_GTL_QS_R_N")
	)
	(arc
		(start 96.778572 -224.057972)
		(mid 96.580344 -223.852124)
		(end 96.508062 -223.575626)
		(width 0.0889)
		(layer "In4.Cu")
		(net "DBP_CPU1_HOOK9_MBP3_GTL_QS_R_N")
	)
	(arc
		(start 93.501464 -223.251268)
		(mid 93.314266 -223.201125)
		(end 93.127068 -223.251268)
		(width 0.0889)
		(layer "In4.Cu")
		(net "DBP_CPU1_HOOK9_MBP3_GTL_QS_R_N")
	)
	(arc
		(start 90.6907 -220.639132)
		(mid 90.869297 -220.319854)
		(end 90.6907 -220.000576)
		(width 0.0889)
		(layer "In4.Cu")
		(net "DBP_CPU1_HOOK9_MBP3_GTL_QS_R_N")
	)
	(arc
		(start 90.399616 -221.111826)
		(mid 90.480527 -220.841698)
		(end 90.68181 -220.644212)
		(width 0.0889)
		(layer "In4.Cu")
		(net "DBP_CPU1_HOOK9_MBP3_GTL_QS_R_N")
	)
	(arc
		(start 89.742264 -219.995496)
		(mid 89.555066 -219.945353)
		(end 89.367868 -219.995496)
		(width 0.0889)
		(layer "In4.Cu")
		(net "DBP_CPU1_HOOK9_MBP3_GTL_QS_R_N")
	)
	(arc
		(start 102.429564 -225.69297)
		(mid 102.242366 -225.642827)
		(end 102.055168 -225.69297)
		(width 0.0889)
		(layer "In4.Cu")
		(net "DBP_CPU1_HOOK9_MBP3_GTL_QS_R_N")
	)
	(arc
		(start 103.839264 -226.506786)
		(mid 103.652066 -226.456643)
		(end 103.464868 -226.506786)
		(width 0.0889)
		(layer "In4.Cu")
		(net "DBP_CPU1_HOOK9_MBP3_GTL_QS_R_N")
	)
	(arc
		(start 103.454454 -226.512882)
		(mid 103.176022 -226.582728)
		(end 102.89921 -226.506786)
		(width 0.0889)
		(layer "In4.Cu")
		(net "DBP_CPU1_HOOK9_MBP3_GTL_QS_R_N")
	)
	(arc
		(start 93.116654 -223.257364)
		(mid 92.838222 -223.327178)
		(end 92.56141 -223.251268)
		(width 0.0889)
		(layer "In4.Cu")
		(net "DBP_CPU1_HOOK9_MBP3_GTL_QS_R_N")
	)
	(segment
		(start 107.411266 -232.250488)
		(end 107.411012 -232.250234)
		(width 0.12954)
		(layer "F.Cu")
		(net "DBP_CPU1_HOOK8_MBP2_GTL_QS_R_N")
	)
	(segment
		(start 107.411012 -232.250234)
		(end 107.411012 -231.714548)
		(width 0.12954)
		(layer "F.Cu")
		(net "DBP_CPU1_HOOK8_MBP2_GTL_QS_R_N")
	)
	(via
		(at 70.369684 -184.330086)
		(size 0.508)
		(drill 0.254)
		(layers "F.Cu" "B.Cu")
		(net "DBP_CPU1_HOOK8_MBP2_GTL_QS_R_N")
	)
	(via
		(at 107.411012 -231.714548)
		(size 0.4572)
		(drill 0.2032)
		(layers "F.Cu" "B.Cu")
		(net "DBP_CPU1_HOOK8_MBP2_GTL_QS_R_N")
	)
	(segment
		(start 70.369684 -183.703976)
		(end 70.369684 -184.330086)
		(width 0.12954)
		(layer "B.Cu")
		(net "DBP_CPU1_HOOK8_MBP2_GTL_QS_R_N")
	)
	(segment
		(start 92.106496 -223.077278)
		(end 92.091764 -223.085914)
		(width 0.0889)
		(layer "In4.Cu")
		(net "DBP_CPU1_HOOK8_MBP2_GTL_QS_R_N")
	)
	(segment
		(start 70.775576 -185.550048)
		(end 70.369684 -185.144156)
		(width 0.127)
		(layer "In4.Cu")
		(net "DBP_CPU1_HOOK8_MBP2_GTL_QS_R_N")
	)
	(segment
		(start 73.752456 -185.550048)
		(end 70.775576 -185.550048)
		(width 0.127)
		(layer "In4.Cu")
		(net "DBP_CPU1_HOOK8_MBP2_GTL_QS_R_N")
	)
	(segment
		(start 96.698816 -223.575626)
		(end 96.698816 -223.561402)
		(width 0.0889)
		(layer "In4.Cu")
		(net "DBP_CPU1_HOOK8_MBP2_GTL_QS_R_N")
	)
	(segment
		(start 102.807516 -226.017328)
		(end 102.807516 -226.003104)
		(width 0.0889)
		(layer "In4.Cu")
		(net "DBP_CPU1_HOOK8_MBP2_GTL_QS_R_N")
	)
	(segment
		(start 86.298278 -214.733886)
		(end 76.628498 -191.388746)
		(width 0.127)
		(layer "In4.Cu")
		(net "DBP_CPU1_HOOK8_MBP2_GTL_QS_R_N")
	)
	(segment
		(start 104.687116 -227.64496)
		(end 104.687116 -227.635054)
		(width 0.0889)
		(layer "In4.Cu")
		(net "DBP_CPU1_HOOK8_MBP2_GTL_QS_R_N")
	)
	(segment
		(start 97.168716 -224.389442)
		(end 97.168716 -224.379536)
		(width 0.0889)
		(layer "In4.Cu")
		(net "DBP_CPU1_HOOK8_MBP2_GTL_QS_R_N")
	)
	(segment
		(start 101.585014 -225.527616)
		(end 101.570282 -225.51898)
		(width 0.0889)
		(layer "In4.Cu")
		(net "DBP_CPU1_HOOK8_MBP2_GTL_QS_R_N")
	)
	(segment
		(start 97.638362 -225.203258)
		(end 97.638362 -225.187764)
		(width 0.0889)
		(layer "In4.Cu")
		(net "DBP_CPU1_HOOK8_MBP2_GTL_QS_R_N")
	)
	(segment
		(start 97.356168 -224.7138)
		(end 97.347278 -224.70872)
		(width 0.0889)
		(layer "In4.Cu")
		(net "DBP_CPU1_HOOK8_MBP2_GTL_QS_R_N")
	)
	(segment
		(start 104.217216 -226.831144)
		(end 104.217216 -226.821238)
		(width 0.0889)
		(layer "In4.Cu")
		(net "DBP_CPU1_HOOK8_MBP2_GTL_QS_R_N")
	)
	(segment
		(start 86.298278 -215.00211)
		(end 86.298278 -214.733886)
		(width 0.127)
		(layer "In4.Cu")
		(net "DBP_CPU1_HOOK8_MBP2_GTL_QS_R_N")
	)
	(segment
		(start 96.886268 -223.899984)
		(end 96.877378 -223.894904)
		(width 0.0889)
		(layer "In4.Cu")
		(net "DBP_CPU1_HOOK8_MBP2_GTL_QS_R_N")
	)
	(segment
		(start 91.060016 -220.334078)
		(end 91.060016 -220.319854)
		(width 0.0889)
		(layer "In4.Cu")
		(net "DBP_CPU1_HOOK8_MBP2_GTL_QS_R_N")
	)
	(segment
		(start 104.404668 -227.155502)
		(end 104.395778 -227.150422)
		(width 0.0889)
		(layer "In4.Cu")
		(net "DBP_CPU1_HOOK8_MBP2_GTL_QS_R_N")
	)
	(segment
		(start 90.777568 -221.458282)
		(end 90.768678 -221.453202)
		(width 0.0889)
		(layer "In4.Cu")
		(net "DBP_CPU1_HOOK8_MBP2_GTL_QS_R_N")
	)
	(segment
		(start 86.549738 -215.25357)
		(end 86.298278 -215.00211)
		(width 0.127)
		(layer "In4.Cu")
		(net "DBP_CPU1_HOOK8_MBP2_GTL_QS_R_N")
	)
	(segment
		(start 107.41025 -230.966264)
		(end 105.836466 -228.17074)
		(width 0.0889)
		(layer "In4.Cu")
		(net "DBP_CPU1_HOOK8_MBP2_GTL_QS_R_N")
	)
	(segment
		(start 87.205058 -215.685116)
		(end 86.981284 -215.685116)
		(width 0.0889)
		(layer "In4.Cu")
		(net "DBP_CPU1_HOOK8_MBP2_GTL_QS_R_N")
	)
	(segment
		(start 90.768678 -220.814646)
		(end 90.777568 -220.809566)
		(width 0.0889)
		(layer "In4.Cu")
		(net "DBP_CPU1_HOOK8_MBP2_GTL_QS_R_N")
	)
	(segment
		(start 70.369684 -185.144156)
		(end 70.369684 -184.330086)
		(width 0.127)
		(layer "In4.Cu")
		(net "DBP_CPU1_HOOK8_MBP2_GTL_QS_R_N")
	)
	(segment
		(start 87.770208 -216.266014)
		(end 87.770208 -216.235026)
		(width 0.0889)
		(layer "In4.Cu")
		(net "DBP_CPU1_HOOK8_MBP2_GTL_QS_R_N")
	)
	(segment
		(start 97.825814 -225.527616)
		(end 97.816924 -225.522536)
		(width 0.0889)
		(layer "In4.Cu")
		(net "DBP_CPU1_HOOK8_MBP2_GTL_QS_R_N")
	)
	(segment
		(start 88.897968 -219.830396)
		(end 88.889078 -219.825316)
		(width 0.0889)
		(layer "In4.Cu")
		(net "DBP_CPU1_HOOK8_MBP2_GTL_QS_R_N")
	)
	(segment
		(start 88.710516 -219.506038)
		(end 88.710516 -219.496132)
		(width 0.0889)
		(layer "In4.Cu")
		(net "DBP_CPU1_HOOK8_MBP2_GTL_QS_R_N")
	)
	(segment
		(start 107.411012 -230.967026)
		(end 107.41025 -230.966264)
		(width 0.0889)
		(layer "In4.Cu")
		(net "DBP_CPU1_HOOK8_MBP2_GTL_QS_R_N")
	)
	(segment
		(start 104.874568 -227.969318)
		(end 104.865678 -227.964238)
		(width 0.0889)
		(layer "In4.Cu")
		(net "DBP_CPU1_HOOK8_MBP2_GTL_QS_R_N")
	)
	(segment
		(start 76.628498 -191.388746)
		(end 76.628498 -188.42609)
		(width 0.127)
		(layer "In4.Cu")
		(net "DBP_CPU1_HOOK8_MBP2_GTL_QS_R_N")
	)
	(segment
		(start 76.628498 -188.42609)
		(end 73.752456 -185.550048)
		(width 0.127)
		(layer "In4.Cu")
		(net "DBP_CPU1_HOOK8_MBP2_GTL_QS_R_N")
	)
	(segment
		(start 100.645214 -225.527616)
		(end 100.630482 -225.51898)
		(width 0.0889)
		(layer "In4.Cu")
		(net "DBP_CPU1_HOOK8_MBP2_GTL_QS_R_N")
	)
	(segment
		(start 91.25331 -222.275654)
		(end 91.247214 -222.272098)
		(width 0.0889)
		(layer "In4.Cu")
		(net "DBP_CPU1_HOOK8_MBP2_GTL_QS_R_N")
	)
	(segment
		(start 86.981284 -215.685116)
		(end 86.549738 -215.25357)
		(width 0.0889)
		(layer "In4.Cu")
		(net "DBP_CPU1_HOOK8_MBP2_GTL_QS_R_N")
	)
	(segment
		(start 87.770462 -217.904314)
		(end 87.770462 -217.864182)
		(width 0.0889)
		(layer "In4.Cu")
		(net "DBP_CPU1_HOOK8_MBP2_GTL_QS_R_N")
	)
	(segment
		(start 91.717368 -223.085914)
		(end 91.708478 -223.080834)
		(width 0.0889)
		(layer "In4.Cu")
		(net "DBP_CPU1_HOOK8_MBP2_GTL_QS_R_N")
	)
	(segment
		(start 98.765614 -225.527616)
		(end 98.750882 -225.51898)
		(width 0.0889)
		(layer "In4.Cu")
		(net "DBP_CPU1_HOOK8_MBP2_GTL_QS_R_N")
	)
	(segment
		(start 107.411012 -231.714548)
		(end 107.411012 -230.967026)
		(width 0.0889)
		(layer "In4.Cu")
		(net "DBP_CPU1_HOOK8_MBP2_GTL_QS_R_N")
	)
	(segment
		(start 93.986096 -223.077278)
		(end 93.971364 -223.085914)
		(width 0.0889)
		(layer "In4.Cu")
		(net "DBP_CPU1_HOOK8_MBP2_GTL_QS_R_N")
	)
	(segment
		(start 87.488014 -217.388694)
		(end 87.479124 -217.383614)
		(width 0.0889)
		(layer "In4.Cu")
		(net "DBP_CPU1_HOOK8_MBP2_GTL_QS_R_N")
	)
	(segment
		(start 91.059762 -221.94774)
		(end 91.059762 -221.932246)
		(width 0.0889)
		(layer "In4.Cu")
		(net "DBP_CPU1_HOOK8_MBP2_GTL_QS_R_N")
	)
	(segment
		(start 91.247214 -222.272098)
		(end 91.238324 -222.267018)
		(width 0.0889)
		(layer "In4.Cu")
		(net "DBP_CPU1_HOOK8_MBP2_GTL_QS_R_N")
	)
	(segment
		(start 87.479124 -216.745058)
		(end 87.488014 -216.739978)
		(width 0.0889)
		(layer "In4.Cu")
		(net "DBP_CPU1_HOOK8_MBP2_GTL_QS_R_N")
	)
	(segment
		(start 102.994968 -226.341686)
		(end 102.986078 -226.336606)
		(width 0.0889)
		(layer "In4.Cu")
		(net "DBP_CPU1_HOOK8_MBP2_GTL_QS_R_N")
	)
	(segment
		(start 102.524814 -225.527616)
		(end 102.510082 -225.51898)
		(width 0.0889)
		(layer "In4.Cu")
		(net "DBP_CPU1_HOOK8_MBP2_GTL_QS_R_N")
	)
	(segment
		(start 95.865696 -223.077278)
		(end 95.850964 -223.085914)
		(width 0.0889)
		(layer "In4.Cu")
		(net "DBP_CPU1_HOOK8_MBP2_GTL_QS_R_N")
	)
	(segment
		(start 105.49001 -228.02723)
		(end 105.0925 -228.02723)
		(width 0.0889)
		(layer "In4.Cu")
		(net "DBP_CPU1_HOOK8_MBP2_GTL_QS_R_N")
	)
	(segment
		(start 90.226896 -219.82176)
		(end 90.212164 -219.830396)
		(width 0.0889)
		(layer "In4.Cu")
		(net "DBP_CPU1_HOOK8_MBP2_GTL_QS_R_N")
	)
	(segment
		(start 88.207596 -218.796616)
		(end 88.04275 -218.511882)
		(width 0.0889)
		(layer "In4.Cu")
		(net "DBP_CPU1_HOOK8_MBP2_GTL_QS_R_N")
	)
	(segment
		(start 99.705414 -225.527616)
		(end 99.690682 -225.51898)
		(width 0.0889)
		(layer "In4.Cu")
		(net "DBP_CPU1_HOOK8_MBP2_GTL_QS_R_N")
	)
	(segment
		(start 90.783664 -219.833952)
		(end 90.777568 -219.830396)
		(width 0.0889)
		(layer "In4.Cu")
		(net "DBP_CPU1_HOOK8_MBP2_GTL_QS_R_N")
	)
	(arc
		(start 96.416368 -223.085914)
		(mid 96.142139 -223.009989)
		(end 95.865696 -223.077278)
		(width 0.0889)
		(layer "In4.Cu")
		(net "DBP_CPU1_HOOK8_MBP2_GTL_QS_R_N")
	)
	(arc
		(start 104.687116 -227.635054)
		(mid 104.609005 -227.358105)
		(end 104.404668 -227.155502)
		(width 0.0889)
		(layer "In4.Cu")
		(net "DBP_CPU1_HOOK8_MBP2_GTL_QS_R_N")
	)
	(arc
		(start 91.060016 -220.319854)
		(mid 90.9861 -220.040352)
		(end 90.783664 -219.833952)
		(width 0.0889)
		(layer "In4.Cu")
		(net "DBP_CPU1_HOOK8_MBP2_GTL_QS_R_N")
	)
	(arc
		(start 91.708478 -223.080834)
		(mid 91.577564 -222.944474)
		(end 91.529916 -222.761556)
		(width 0.0889)
		(layer "In4.Cu")
		(net "DBP_CPU1_HOOK8_MBP2_GTL_QS_R_N")
	)
	(arc
		(start 100.07981 -225.527616)
		(mid 99.892612 -225.577759)
		(end 99.705414 -225.527616)
		(width 0.0889)
		(layer "In4.Cu")
		(net "DBP_CPU1_HOOK8_MBP2_GTL_QS_R_N")
	)
	(arc
		(start 96.698816 -223.561402)
		(mid 96.619675 -223.286779)
		(end 96.416368 -223.085914)
		(width 0.0889)
		(layer "In4.Cu")
		(net "DBP_CPU1_HOOK8_MBP2_GTL_QS_R_N")
	)
	(arc
		(start 90.777568 -219.830396)
		(mid 90.503369 -219.754561)
		(end 90.226896 -219.82176)
		(width 0.0889)
		(layer "In4.Cu")
		(net "DBP_CPU1_HOOK8_MBP2_GTL_QS_R_N")
	)
	(arc
		(start 104.217216 -226.821238)
		(mid 104.139105 -226.544289)
		(end 103.934768 -226.341686)
		(width 0.0889)
		(layer "In4.Cu")
		(net "DBP_CPU1_HOOK8_MBP2_GTL_QS_R_N")
	)
	(arc
		(start 91.238324 -222.267018)
		(mid 91.10741 -222.130658)
		(end 91.059762 -221.94774)
		(width 0.0889)
		(layer "In4.Cu")
		(net "DBP_CPU1_HOOK8_MBP2_GTL_QS_R_N")
	)
	(arc
		(start 103.369364 -226.341686)
		(mid 103.182166 -226.391829)
		(end 102.994968 -226.341686)
		(width 0.0889)
		(layer "In4.Cu")
		(net "DBP_CPU1_HOOK8_MBP2_GTL_QS_R_N")
	)
	(arc
		(start 89.272364 -219.830396)
		(mid 89.085166 -219.880539)
		(end 88.897968 -219.830396)
		(width 0.0889)
		(layer "In4.Cu")
		(net "DBP_CPU1_HOOK8_MBP2_GTL_QS_R_N")
	)
	(arc
		(start 88.710516 -219.496132)
		(mid 88.632405 -219.219183)
		(end 88.428068 -219.01658)
		(width 0.0889)
		(layer "In4.Cu")
		(net "DBP_CPU1_HOOK8_MBP2_GTL_QS_R_N")
	)
	(arc
		(start 97.347278 -224.70872)
		(mid 97.216364 -224.57236)
		(end 97.168716 -224.389442)
		(width 0.0889)
		(layer "In4.Cu")
		(net "DBP_CPU1_HOOK8_MBP2_GTL_QS_R_N")
	)
	(arc
		(start 102.510082 -225.51898)
		(mid 102.233641 -225.451814)
		(end 101.95941 -225.527616)
		(width 0.0889)
		(layer "In4.Cu")
		(net "DBP_CPU1_HOOK8_MBP2_GTL_QS_R_N")
	)
	(arc
		(start 97.816924 -225.522536)
		(mid 97.68601 -225.386176)
		(end 97.638362 -225.203258)
		(width 0.0889)
		(layer "In4.Cu")
		(net "DBP_CPU1_HOOK8_MBP2_GTL_QS_R_N")
	)
	(arc
		(start 88.428068 -219.01658)
		(mid 88.303388 -218.921074)
		(end 88.207596 -218.796616)
		(width 0.0889)
		(layer "In4.Cu")
		(net "DBP_CPU1_HOOK8_MBP2_GTL_QS_R_N")
	)
	(arc
		(start 101.01961 -225.527616)
		(mid 100.832412 -225.577759)
		(end 100.645214 -225.527616)
		(width 0.0889)
		(layer "In4.Cu")
		(net "DBP_CPU1_HOOK8_MBP2_GTL_QS_R_N")
	)
	(arc
		(start 90.768678 -221.453202)
		(mid 90.590081 -221.133924)
		(end 90.768678 -220.814646)
		(width 0.0889)
		(layer "In4.Cu")
		(net "DBP_CPU1_HOOK8_MBP2_GTL_QS_R_N")
	)
	(arc
		(start 94.536768 -223.085914)
		(mid 94.262539 -223.009989)
		(end 93.986096 -223.077278)
		(width 0.0889)
		(layer "In4.Cu")
		(net "DBP_CPU1_HOOK8_MBP2_GTL_QS_R_N")
	)
	(arc
		(start 97.168716 -224.379536)
		(mid 97.090605 -224.102587)
		(end 96.886268 -223.899984)
		(width 0.0889)
		(layer "In4.Cu")
		(net "DBP_CPU1_HOOK8_MBP2_GTL_QS_R_N")
	)
	(arc
		(start 91.529916 -222.761556)
		(mid 91.455925 -222.48199)
		(end 91.25331 -222.275654)
		(width 0.0889)
		(layer "In4.Cu")
		(net "DBP_CPU1_HOOK8_MBP2_GTL_QS_R_N")
	)
	(arc
		(start 87.770462 -217.864182)
		(mid 87.691321 -217.589559)
		(end 87.488014 -217.388694)
		(width 0.0889)
		(layer "In4.Cu")
		(net "DBP_CPU1_HOOK8_MBP2_GTL_QS_R_N")
	)
	(arc
		(start 95.476568 -223.085914)
		(mid 95.193866 -223.010172)
		(end 94.911164 -223.085914)
		(width 0.0889)
		(layer "In4.Cu")
		(net "DBP_CPU1_HOOK8_MBP2_GTL_QS_R_N")
	)
	(arc
		(start 92.657168 -223.085914)
		(mid 92.382939 -223.009989)
		(end 92.106496 -223.077278)
		(width 0.0889)
		(layer "In4.Cu")
		(net "DBP_CPU1_HOOK8_MBP2_GTL_QS_R_N")
	)
	(arc
		(start 93.971364 -223.085914)
		(mid 93.784166 -223.136057)
		(end 93.596968 -223.085914)
		(width 0.0889)
		(layer "In4.Cu")
		(net "DBP_CPU1_HOOK8_MBP2_GTL_QS_R_N")
	)
	(arc
		(start 93.596968 -223.085914)
		(mid 93.314266 -223.010172)
		(end 93.031564 -223.085914)
		(width 0.0889)
		(layer "In4.Cu")
		(net "DBP_CPU1_HOOK8_MBP2_GTL_QS_R_N")
	)
	(arc
		(start 90.212164 -219.830396)
		(mid 90.024966 -219.880539)
		(end 89.837768 -219.830396)
		(width 0.0889)
		(layer "In4.Cu")
		(net "DBP_CPU1_HOOK8_MBP2_GTL_QS_R_N")
	)
	(arc
		(start 91.059762 -221.932246)
		(mid 90.980392 -221.658512)
		(end 90.777568 -221.458282)
		(width 0.0889)
		(layer "In4.Cu")
		(net "DBP_CPU1_HOOK8_MBP2_GTL_QS_R_N")
	)
	(arc
		(start 98.20021 -225.527616)
		(mid 98.013012 -225.577759)
		(end 97.825814 -225.527616)
		(width 0.0889)
		(layer "In4.Cu")
		(net "DBP_CPU1_HOOK8_MBP2_GTL_QS_R_N")
	)
	(arc
		(start 98.750882 -225.51898)
		(mid 98.474441 -225.451814)
		(end 98.20021 -225.527616)
		(width 0.0889)
		(layer "In4.Cu")
		(net "DBP_CPU1_HOOK8_MBP2_GTL_QS_R_N")
	)
	(arc
		(start 87.770208 -216.235026)
		(mid 87.690838 -215.961292)
		(end 87.488014 -215.761062)
		(width 0.0889)
		(layer "In4.Cu")
		(net "DBP_CPU1_HOOK8_MBP2_GTL_QS_R_N")
	)
	(arc
		(start 88.04275 -218.511882)
		(mid 87.966532 -218.396151)
		(end 87.888318 -218.281758)
		(width 0.0889)
		(layer "In4.Cu")
		(net "DBP_CPU1_HOOK8_MBP2_GTL_QS_R_N")
	)
	(arc
		(start 87.488014 -216.739978)
		(mid 87.690837 -216.539747)
		(end 87.770208 -216.266014)
		(width 0.0889)
		(layer "In4.Cu")
		(net "DBP_CPU1_HOOK8_MBP2_GTL_QS_R_N")
	)
	(arc
		(start 95.850964 -223.085914)
		(mid 95.663766 -223.136057)
		(end 95.476568 -223.085914)
		(width 0.0889)
		(layer "In4.Cu")
		(net "DBP_CPU1_HOOK8_MBP2_GTL_QS_R_N")
	)
	(arc
		(start 96.877378 -223.894904)
		(mid 96.746464 -223.758544)
		(end 96.698816 -223.575626)
		(width 0.0889)
		(layer "In4.Cu")
		(net "DBP_CPU1_HOOK8_MBP2_GTL_QS_R_N")
	)
	(arc
		(start 93.031564 -223.085914)
		(mid 92.844366 -223.136057)
		(end 92.657168 -223.085914)
		(width 0.0889)
		(layer "In4.Cu")
		(net "DBP_CPU1_HOOK8_MBP2_GTL_QS_R_N")
	)
	(arc
		(start 88.889078 -219.825316)
		(mid 88.758164 -219.688956)
		(end 88.710516 -219.506038)
		(width 0.0889)
		(layer "In4.Cu")
		(net "DBP_CPU1_HOOK8_MBP2_GTL_QS_R_N")
	)
	(arc
		(start 102.986078 -226.336606)
		(mid 102.855164 -226.200246)
		(end 102.807516 -226.017328)
		(width 0.0889)
		(layer "In4.Cu")
		(net "DBP_CPU1_HOOK8_MBP2_GTL_QS_R_N")
	)
	(arc
		(start 92.091764 -223.085914)
		(mid 91.904566 -223.136057)
		(end 91.717368 -223.085914)
		(width 0.0889)
		(layer "In4.Cu")
		(net "DBP_CPU1_HOOK8_MBP2_GTL_QS_R_N")
	)
	(arc
		(start 89.837768 -219.830396)
		(mid 89.555066 -219.75462)
		(end 89.272364 -219.830396)
		(width 0.0889)
		(layer "In4.Cu")
		(net "DBP_CPU1_HOOK8_MBP2_GTL_QS_R_N")
	)
	(arc
		(start 102.807516 -226.003104)
		(mid 102.728297 -225.728419)
		(end 102.524814 -225.527616)
		(width 0.0889)
		(layer "In4.Cu")
		(net "DBP_CPU1_HOOK8_MBP2_GTL_QS_R_N")
	)
	(arc
		(start 97.638362 -225.187764)
		(mid 97.558992 -224.91403)
		(end 97.356168 -224.7138)
		(width 0.0889)
		(layer "In4.Cu")
		(net "DBP_CPU1_HOOK8_MBP2_GTL_QS_R_N")
	)
	(arc
		(start 90.777568 -220.809566)
		(mid 90.980873 -220.6087)
		(end 91.060016 -220.334078)
		(width 0.0889)
		(layer "In4.Cu")
		(net "DBP_CPU1_HOOK8_MBP2_GTL_QS_R_N")
	)
	(arc
		(start 99.14001 -225.527616)
		(mid 98.952812 -225.577759)
		(end 98.765614 -225.527616)
		(width 0.0889)
		(layer "In4.Cu")
		(net "DBP_CPU1_HOOK8_MBP2_GTL_QS_R_N")
	)
	(arc
		(start 99.690682 -225.51898)
		(mid 99.414241 -225.451814)
		(end 99.14001 -225.527616)
		(width 0.0889)
		(layer "In4.Cu")
		(net "DBP_CPU1_HOOK8_MBP2_GTL_QS_R_N")
	)
	(arc
		(start 105.0925 -228.02723)
		(mid 104.979745 -228.012517)
		(end 104.874568 -227.969318)
		(width 0.0889)
		(layer "In4.Cu")
		(net "DBP_CPU1_HOOK8_MBP2_GTL_QS_R_N")
	)
	(arc
		(start 87.488014 -215.761062)
		(mid 87.351542 -215.704439)
		(end 87.205058 -215.685116)
		(width 0.0889)
		(layer "In4.Cu")
		(net "DBP_CPU1_HOOK8_MBP2_GTL_QS_R_N")
	)
	(arc
		(start 104.395778 -227.150422)
		(mid 104.264864 -227.014062)
		(end 104.217216 -226.831144)
		(width 0.0889)
		(layer "In4.Cu")
		(net "DBP_CPU1_HOOK8_MBP2_GTL_QS_R_N")
	)
	(arc
		(start 104.865678 -227.964238)
		(mid 104.734764 -227.827878)
		(end 104.687116 -227.64496)
		(width 0.0889)
		(layer "In4.Cu")
		(net "DBP_CPU1_HOOK8_MBP2_GTL_QS_R_N")
	)
	(arc
		(start 101.95941 -225.527616)
		(mid 101.772212 -225.577759)
		(end 101.585014 -225.527616)
		(width 0.0889)
		(layer "In4.Cu")
		(net "DBP_CPU1_HOOK8_MBP2_GTL_QS_R_N")
	)
	(arc
		(start 103.934768 -226.341686)
		(mid 103.652066 -226.26591)
		(end 103.369364 -226.341686)
		(width 0.0889)
		(layer "In4.Cu")
		(net "DBP_CPU1_HOOK8_MBP2_GTL_QS_R_N")
	)
	(arc
		(start 105.836466 -228.17074)
		(mid 105.677511 -228.064529)
		(end 105.49001 -228.02723)
		(width 0.0889)
		(layer "In4.Cu")
		(net "DBP_CPU1_HOOK8_MBP2_GTL_QS_R_N")
	)
	(arc
		(start 101.570282 -225.51898)
		(mid 101.293841 -225.451814)
		(end 101.01961 -225.527616)
		(width 0.0889)
		(layer "In4.Cu")
		(net "DBP_CPU1_HOOK8_MBP2_GTL_QS_R_N")
	)
	(arc
		(start 87.479124 -217.383614)
		(mid 87.300527 -217.064336)
		(end 87.479124 -216.745058)
		(width 0.0889)
		(layer "In4.Cu")
		(net "DBP_CPU1_HOOK8_MBP2_GTL_QS_R_N")
	)
	(arc
		(start 87.888318 -218.281758)
		(mid 87.800564 -218.102036)
		(end 87.770462 -217.904314)
		(width 0.0889)
		(layer "In4.Cu")
		(net "DBP_CPU1_HOOK8_MBP2_GTL_QS_R_N")
	)
	(arc
		(start 100.630482 -225.51898)
		(mid 100.354041 -225.451814)
		(end 100.07981 -225.527616)
		(width 0.0889)
		(layer "In4.Cu")
		(net "DBP_CPU1_HOOK8_MBP2_GTL_QS_R_N")
	)
	(arc
		(start 94.911164 -223.085914)
		(mid 94.723966 -223.136057)
		(end 94.536768 -223.085914)
		(width 0.0889)
		(layer "In4.Cu")
		(net "DBP_CPU1_HOOK8_MBP2_GTL_QS_R_N")
	)
	(segment
		(start 357.230934 -233.87812)
		(end 357.23068 -233.877866)
		(width 0.12954)
		(layer "F.Cu")
		(net "DBP_CPU0_MBP1_GTL_R_N")
	)
	(segment
		(start 357.23068 -233.877866)
		(end 357.23068 -233.34218)
		(width 0.12954)
		(layer "F.Cu")
		(net "DBP_CPU0_MBP1_GTL_R_N")
	)
	(via
		(at 357.23068 -233.34218)
		(size 0.4572)
		(drill 0.2032)
		(layers "F.Cu" "B.Cu")
		(net "DBP_CPU0_MBP1_GTL_R_N")
	)
	(via
		(at 331.902054 -201.873866)
		(size 0.508)
		(drill 0.254)
		(layers "F.Cu" "B.Cu")
		(net "DBP_CPU0_MBP1_GTL_R_N")
	)
	(via
		(at 335.288128 -197.03415)
		(size 0.6604)
		(drill 0.3302)
		(layers "F.Cu" "B.Cu")
		(net "DBP_CPU0_MBP1_GTL_R_N")
	)
	(segment
		(start 332.97622 -201.843386)
		(end 332.182724 -202.042014)
		(width 0.12954)
		(layer "B.Cu")
		(net "DBP_CPU0_MBP1_GTL_R_N")
	)
	(segment
		(start 335.344516 -197.208648)
		(end 332.97622 -201.843386)
		(width 0.12954)
		(layer "B.Cu")
		(net "DBP_CPU0_MBP1_GTL_R_N")
	)
	(segment
		(start 335.288128 -191.22898)
		(end 335.288128 -197.03415)
		(width 0.12954)
		(layer "B.Cu")
		(net "DBP_CPU0_MBP1_GTL_R_N")
	)
	(segment
		(start 332.182724 -202.042014)
		(end 331.902054 -201.873866)
		(width 0.12954)
		(layer "B.Cu")
		(net "DBP_CPU0_MBP1_GTL_R_N")
	)
	(segment
		(start 335.288128 -197.03415)
		(end 335.344516 -197.208648)
		(width 0.12954)
		(layer "B.Cu")
		(net "DBP_CPU0_MBP1_GTL_R_N")
	)
	(segment
		(start 340.986364 -219.190316)
		(end 340.971632 -219.18168)
		(width 0.0889)
		(layer "In4.Cu")
		(net "DBP_CPU0_MBP1_GTL_R_N")
	)
	(segment
		(start 355.33203 -224.81921)
		(end 354.974144 -224.81921)
		(width 0.0889)
		(layer "In4.Cu")
		(net "DBP_CPU0_MBP1_GTL_R_N")
	)
	(segment
		(start 356.572058 -228.06025)
		(end 356.489508 -227.9777)
		(width 0.0889)
		(layer "In4.Cu")
		(net "DBP_CPU0_MBP1_GTL_R_N")
	)
	(segment
		(start 356.438454 -228.897434)
		(end 356.572058 -228.76383)
		(width 0.0889)
		(layer "In4.Cu")
		(net "DBP_CPU0_MBP1_GTL_R_N")
	)
	(segment
		(start 332.079346 -209.949796)
		(end 332.079346 -202.051158)
		(width 0.127)
		(layer "In4.Cu")
		(net "DBP_CPU0_MBP1_GTL_R_N")
	)
	(segment
		(start 356.149402 -225.648774)
		(end 355.855778 -225.35515)
		(width 0.0889)
		(layer "In4.Cu")
		(net "DBP_CPU0_MBP1_GTL_R_N")
	)
	(segment
		(start 348.20733 -220.327474)
		(end 348.20733 -220.319854)
		(width 0.0889)
		(layer "In4.Cu")
		(net "DBP_CPU0_MBP1_GTL_R_N")
	)
	(segment
		(start 352.344736 -223.251268)
		(end 352.334322 -223.257364)
		(width 0.0889)
		(layer "In4.Cu")
		(net "DBP_CPU0_MBP1_GTL_R_N")
	)
	(segment
		(start 338.166964 -219.190316)
		(end 338.152232 -219.18168)
		(width 0.0889)
		(layer "In4.Cu")
		(net "DBP_CPU0_MBP1_GTL_R_N")
	)
	(segment
		(start 332.079346 -202.051158)
		(end 331.902054 -201.873866)
		(width 0.127)
		(layer "In4.Cu")
		(net "DBP_CPU0_MBP1_GTL_R_N")
	)
	(segment
		(start 355.649276 -224.970848)
		(end 355.614732 -224.936304)
		(width 0.0889)
		(layer "In4.Cu")
		(net "DBP_CPU0_MBP1_GTL_R_N")
	)
	(segment
		(start 349.551498 -223.13773)
		(end 349.17253 -223.13773)
		(width 0.0889)
		(layer "In4.Cu")
		(net "DBP_CPU0_MBP1_GTL_R_N")
	)
	(segment
		(start 344.745564 -219.190316)
		(end 344.730832 -219.18168)
		(width 0.0889)
		(layer "In4.Cu")
		(net "DBP_CPU0_MBP1_GTL_R_N")
	)
	(segment
		(start 340.046564 -219.190316)
		(end 340.031832 -219.18168)
		(width 0.0889)
		(layer "In4.Cu")
		(net "DBP_CPU0_MBP1_GTL_R_N")
	)
	(segment
		(start 335.98993 -217.07856)
		(end 335.98993 -217.064336)
		(width 0.0889)
		(layer "In4.Cu")
		(net "DBP_CPU0_MBP1_GTL_R_N")
	)
	(segment
		(start 334.711802 -216.310972)
		(end 332.079346 -209.949796)
		(width 0.127)
		(layer "In4.Cu")
		(net "DBP_CPU0_MBP1_GTL_R_N")
	)
	(segment
		(start 356.478586 -227.389182)
		(end 356.479856 -227.387658)
		(width 0.0889)
		(layer "In4.Cu")
		(net "DBP_CPU0_MBP1_GTL_R_N")
	)
	(segment
		(start 350.465136 -223.251268)
		(end 350.454722 -223.257364)
		(width 0.0889)
		(layer "In4.Cu")
		(net "DBP_CPU0_MBP1_GTL_R_N")
	)
	(segment
		(start 334.920082 -216.570814)
		(end 334.815688 -216.46642)
		(width 0.0889)
		(layer "In4.Cu")
		(net "DBP_CPU0_MBP1_GTL_R_N")
	)
	(segment
		(start 357.426768 -231.39527)
		(end 357.417878 -231.39019)
		(width 0.0889)
		(layer "In4.Cu")
		(net "DBP_CPU0_MBP1_GTL_R_N")
	)
	(segment
		(start 345.795854 -219.255086)
		(end 345.670632 -219.18168)
		(width 0.0889)
		(layer "In4.Cu")
		(net "DBP_CPU0_MBP1_GTL_R_N")
	)
	(segment
		(start 341.926164 -219.190316)
		(end 341.911432 -219.18168)
		(width 0.0889)
		(layer "In4.Cu")
		(net "DBP_CPU0_MBP1_GTL_R_N")
	)
	(segment
		(start 348.590362 -222.480632)
		(end 348.339918 -221.98457)
		(width 0.0889)
		(layer "In4.Cu")
		(net "DBP_CPU0_MBP1_GTL_R_N")
	)
	(segment
		(start 353.284282 -223.251268)
		(end 353.273868 -223.257364)
		(width 0.0889)
		(layer "In4.Cu")
		(net "DBP_CPU0_MBP1_GTL_R_N")
	)
	(segment
		(start 348.028768 -220.000576)
		(end 348.019878 -219.995496)
		(width 0.0889)
		(layer "In4.Cu")
		(net "DBP_CPU0_MBP1_GTL_R_N")
	)
	(segment
		(start 346.159074 -219.773246)
		(end 346.136722 -219.750894)
		(width 0.0889)
		(layer "In4.Cu")
		(net "DBP_CPU0_MBP1_GTL_R_N")
	)
	(segment
		(start 356.948232 -230.57612)
		(end 356.942136 -230.572564)
		(width 0.0889)
		(layer "In4.Cu")
		(net "DBP_CPU0_MBP1_GTL_R_N")
	)
	(segment
		(start 351.404682 -223.251268)
		(end 351.394268 -223.257364)
		(width 0.0889)
		(layer "In4.Cu")
		(net "DBP_CPU0_MBP1_GTL_R_N")
	)
	(segment
		(start 357.417878 -232.038906)
		(end 357.426768 -232.033826)
		(width 0.0889)
		(layer "In4.Cu")
		(net "DBP_CPU0_MBP1_GTL_R_N")
	)
	(segment
		(start 336.460084 -217.888312)
		(end 336.460084 -217.878406)
		(width 0.0889)
		(layer "In4.Cu")
		(net "DBP_CPU0_MBP1_GTL_R_N")
	)
	(segment
		(start 349.013018 -223.07169)
		(end 348.825566 -222.884238)
		(width 0.0889)
		(layer "In4.Cu")
		(net "DBP_CPU0_MBP1_GTL_R_N")
	)
	(segment
		(start 346.692728 -219.89161)
		(end 346.444824 -219.89161)
		(width 0.0889)
		(layer "In4.Cu")
		(net "DBP_CPU0_MBP1_GTL_R_N")
	)
	(segment
		(start 342.865964 -219.190316)
		(end 342.851232 -219.18168)
		(width 0.0889)
		(layer "In4.Cu")
		(net "DBP_CPU0_MBP1_GTL_R_N")
	)
	(segment
		(start 336.281522 -217.559128)
		(end 336.272632 -217.554048)
		(width 0.0889)
		(layer "In4.Cu")
		(net "DBP_CPU0_MBP1_GTL_R_N")
	)
	(segment
		(start 336.92973 -218.692222)
		(end 336.92973 -218.683586)
		(width 0.0889)
		(layer "In4.Cu")
		(net "DBP_CPU0_MBP1_GTL_R_N")
	)
	(segment
		(start 357.135684 -232.543858)
		(end 357.135684 -232.51287)
		(width 0.0889)
		(layer "In4.Cu")
		(net "DBP_CPU0_MBP1_GTL_R_N")
	)
	(segment
		(start 343.805764 -219.190316)
		(end 343.791032 -219.18168)
		(width 0.0889)
		(layer "In4.Cu")
		(net "DBP_CPU0_MBP1_GTL_R_N")
	)
	(segment
		(start 354.575618 -224.65411)
		(end 354.508054 -224.586546)
		(width 0.0889)
		(layer "In4.Cu")
		(net "DBP_CPU0_MBP1_GTL_R_N")
	)
	(segment
		(start 337.212432 -219.18168)
		(end 337.206336 -219.178124)
		(width 0.0889)
		(layer "In4.Cu")
		(net "DBP_CPU0_MBP1_GTL_R_N")
	)
	(segment
		(start 356.459028 -226.373182)
		(end 356.432866 -226.34702)
		(width 0.0889)
		(layer "In4.Cu")
		(net "DBP_CPU0_MBP1_GTL_R_N")
	)
	(segment
		(start 347.925136 -221.187518)
		(end 347.915484 -221.11462)
		(width 0.0889)
		(layer "In4.Cu")
		(net "DBP_CPU0_MBP1_GTL_R_N")
	)
	(segment
		(start 339.106764 -219.190316)
		(end 339.092032 -219.18168)
		(width 0.0889)
		(layer "In4.Cu")
		(net "DBP_CPU0_MBP1_GTL_R_N")
	)
	(segment
		(start 349.899478 -223.251268)
		(end 349.8342 -223.213422)
		(width 0.0889)
		(layer "In4.Cu")
		(net "DBP_CPU0_MBP1_GTL_R_N")
	)
	(segment
		(start 347.954854 -221.281244)
		(end 347.936058 -221.230444)
		(width 0.0889)
		(layer "In4.Cu")
		(net "DBP_CPU0_MBP1_GTL_R_N")
	)
	(segment
		(start 347.645482 -219.995496)
		(end 347.635068 -220.001592)
		(width 0.0889)
		(layer "In4.Cu")
		(net "DBP_CPU0_MBP1_GTL_R_N")
	)
	(segment
		(start 348.720664 -222.631)
		(end 348.642178 -222.552514)
		(width 0.0889)
		(layer "In4.Cu")
		(net "DBP_CPU0_MBP1_GTL_R_N")
	)
	(segment
		(start 353.717606 -223.28505)
		(end 353.658678 -223.251268)
		(width 0.0889)
		(layer "In4.Cu")
		(net "DBP_CPU0_MBP1_GTL_R_N")
	)
	(segment
		(start 357.13543 -230.91902)
		(end 357.13543 -230.891842)
		(width 0.0889)
		(layer "In4.Cu")
		(net "DBP_CPU0_MBP1_GTL_R_N")
	)
	(segment
		(start 335.550256 -216.681812)
		(end 334.998314 -216.609422)
		(width 0.0889)
		(layer "In4.Cu")
		(net "DBP_CPU0_MBP1_GTL_R_N")
	)
	(segment
		(start 337.227164 -219.190316)
		(end 337.212432 -219.18168)
		(width 0.0889)
		(layer "In4.Cu")
		(net "DBP_CPU0_MBP1_GTL_R_N")
	)
	(segment
		(start 356.239064 -225.878898)
		(end 356.239064 -225.865436)
		(width 0.0889)
		(layer "In4.Cu")
		(net "DBP_CPU0_MBP1_GTL_R_N")
	)
	(arc
		(start 346.136722 -219.750894)
		(mid 346.061736 -219.653343)
		(end 346.014294 -219.53982)
		(width 0.0889)
		(layer "In4.Cu")
		(net "DBP_CPU0_MBP1_GTL_R_N")
	)
	(arc
		(start 356.406958 -229.46233)
		(mid 356.373888 -229.21962)
		(end 356.396036 -228.975666)
		(width 0.0889)
		(layer "In4.Cu")
		(net "DBP_CPU0_MBP1_GTL_R_N")
	)
	(arc
		(start 348.642178 -222.552514)
		(mid 348.613417 -222.518631)
		(end 348.590362 -222.480632)
		(width 0.0889)
		(layer "In4.Cu")
		(net "DBP_CPU0_MBP1_GTL_R_N")
	)
	(arc
		(start 348.066106 -220.668342)
		(mid 348.170604 -220.51195)
		(end 348.20733 -220.327474)
		(width 0.0889)
		(layer "In4.Cu")
		(net "DBP_CPU0_MBP1_GTL_R_N")
	)
	(arc
		(start 356.43439 -227.452428)
		(mid 356.454256 -227.419245)
		(end 356.478586 -227.389182)
		(width 0.0889)
		(layer "In4.Cu")
		(net "DBP_CPU0_MBP1_GTL_R_N")
	)
	(arc
		(start 354.255324 -224.063814)
		(mid 354.035117 -223.693848)
		(end 353.784916 -223.34347)
		(width 0.0889)
		(layer "In4.Cu")
		(net "DBP_CPU0_MBP1_GTL_R_N")
	)
	(arc
		(start 349.17253 -223.13773)
		(mid 349.086215 -223.120561)
		(end 349.013018 -223.07169)
		(width 0.0889)
		(layer "In4.Cu")
		(net "DBP_CPU0_MBP1_GTL_R_N")
	)
	(arc
		(start 339.657436 -219.18168)
		(mid 339.383237 -219.257515)
		(end 339.106764 -219.190316)
		(width 0.0889)
		(layer "In4.Cu")
		(net "DBP_CPU0_MBP1_GTL_R_N")
	)
	(arc
		(start 351.779078 -223.251268)
		(mid 351.59188 -223.201125)
		(end 351.404682 -223.251268)
		(width 0.0889)
		(layer "In4.Cu")
		(net "DBP_CPU0_MBP1_GTL_R_N")
	)
	(arc
		(start 356.479856 -227.387658)
		(mid 356.673472 -226.876252)
		(end 356.459028 -226.373182)
		(width 0.0889)
		(layer "In4.Cu")
		(net "DBP_CPU0_MBP1_GTL_R_N")
	)
	(arc
		(start 348.753938 -222.711264)
		(mid 348.74528 -222.667829)
		(end 348.720664 -222.631)
		(width 0.0889)
		(layer "In4.Cu")
		(net "DBP_CPU0_MBP1_GTL_R_N")
	)
	(arc
		(start 335.638902 -216.690448)
		(mid 335.594506 -216.686883)
		(end 335.550256 -216.681812)
		(width 0.0889)
		(layer "In4.Cu")
		(net "DBP_CPU0_MBP1_GTL_R_N")
	)
	(arc
		(start 355.855778 -225.35515)
		(mid 355.768045 -225.237295)
		(end 355.71811 -225.099118)
		(width 0.0889)
		(layer "In4.Cu")
		(net "DBP_CPU0_MBP1_GTL_R_N")
	)
	(arc
		(start 356.436676 -227.905818)
		(mid 356.381199 -227.679406)
		(end 356.43439 -227.452428)
		(width 0.0889)
		(layer "In4.Cu")
		(net "DBP_CPU0_MBP1_GTL_R_N")
	)
	(arc
		(start 346.444824 -219.89161)
		(mid 346.290176 -219.860849)
		(end 346.159074 -219.773246)
		(width 0.0889)
		(layer "In4.Cu")
		(net "DBP_CPU0_MBP1_GTL_R_N")
	)
	(arc
		(start 356.432866 -226.34702)
		(mid 356.289411 -226.13223)
		(end 356.239064 -225.878898)
		(width 0.0889)
		(layer "In4.Cu")
		(net "DBP_CPU0_MBP1_GTL_R_N")
	)
	(arc
		(start 343.791032 -219.18168)
		(mid 343.603834 -219.131537)
		(end 343.416636 -219.18168)
		(width 0.0889)
		(layer "In4.Cu")
		(net "DBP_CPU0_MBP1_GTL_R_N")
	)
	(arc
		(start 355.71811 -225.099118)
		(mid 355.693145 -225.029918)
		(end 355.649276 -224.970848)
		(width 0.0889)
		(layer "In4.Cu")
		(net "DBP_CPU0_MBP1_GTL_R_N")
	)
	(arc
		(start 343.416636 -219.18168)
		(mid 343.142437 -219.257515)
		(end 342.865964 -219.190316)
		(width 0.0889)
		(layer "In4.Cu")
		(net "DBP_CPU0_MBP1_GTL_R_N")
	)
	(arc
		(start 348.20733 -220.319854)
		(mid 348.159651 -220.136954)
		(end 348.028768 -220.000576)
		(width 0.0889)
		(layer "In4.Cu")
		(net "DBP_CPU0_MBP1_GTL_R_N")
	)
	(arc
		(start 348.339918 -221.98457)
		(mid 348.271118 -221.859)
		(end 348.193868 -221.738444)
		(width 0.0889)
		(layer "In4.Cu")
		(net "DBP_CPU0_MBP1_GTL_R_N")
	)
	(arc
		(start 347.080332 -219.995496)
		(mid 346.893371 -219.918025)
		(end 346.692728 -219.89161)
		(width 0.0889)
		(layer "In4.Cu")
		(net "DBP_CPU0_MBP1_GTL_R_N")
	)
	(arc
		(start 350.454722 -223.257364)
		(mid 350.17629 -223.327178)
		(end 349.899478 -223.251268)
		(width 0.0889)
		(layer "In4.Cu")
		(net "DBP_CPU0_MBP1_GTL_R_N")
	)
	(arc
		(start 338.717636 -219.18168)
		(mid 338.443437 -219.257515)
		(end 338.166964 -219.190316)
		(width 0.0889)
		(layer "In4.Cu")
		(net "DBP_CPU0_MBP1_GTL_R_N")
	)
	(arc
		(start 357.135684 -232.51287)
		(mid 357.215054 -232.239136)
		(end 357.417878 -232.038906)
		(width 0.0889)
		(layer "In4.Cu")
		(net "DBP_CPU0_MBP1_GTL_R_N")
	)
	(arc
		(start 337.206336 -219.178124)
		(mid 337.003749 -218.971773)
		(end 336.92973 -218.692222)
		(width 0.0889)
		(layer "In4.Cu")
		(net "DBP_CPU0_MBP1_GTL_R_N")
	)
	(arc
		(start 357.417878 -231.39019)
		(mid 357.215592 -231.191209)
		(end 357.13543 -230.91902)
		(width 0.0889)
		(layer "In4.Cu")
		(net "DBP_CPU0_MBP1_GTL_R_N")
	)
	(arc
		(start 340.031832 -219.18168)
		(mid 339.844634 -219.131537)
		(end 339.657436 -219.18168)
		(width 0.0889)
		(layer "In4.Cu")
		(net "DBP_CPU0_MBP1_GTL_R_N")
	)
	(arc
		(start 336.742532 -218.367864)
		(mid 336.538197 -218.165259)
		(end 336.460084 -217.888312)
		(width 0.0889)
		(layer "In4.Cu")
		(net "DBP_CPU0_MBP1_GTL_R_N")
	)
	(arc
		(start 357.426768 -232.033826)
		(mid 357.605365 -231.714548)
		(end 357.426768 -231.39527)
		(width 0.0889)
		(layer "In4.Cu")
		(net "DBP_CPU0_MBP1_GTL_R_N")
	)
	(arc
		(start 342.851232 -219.18168)
		(mid 342.664034 -219.131537)
		(end 342.476836 -219.18168)
		(width 0.0889)
		(layer "In4.Cu")
		(net "DBP_CPU0_MBP1_GTL_R_N")
	)
	(arc
		(start 352.719132 -223.251268)
		(mid 352.531934 -223.201125)
		(end 352.344736 -223.251268)
		(width 0.0889)
		(layer "In4.Cu")
		(net "DBP_CPU0_MBP1_GTL_R_N")
	)
	(arc
		(start 341.537036 -219.18168)
		(mid 341.262837 -219.257515)
		(end 340.986364 -219.190316)
		(width 0.0889)
		(layer "In4.Cu")
		(net "DBP_CPU0_MBP1_GTL_R_N")
	)
	(arc
		(start 344.356436 -219.18168)
		(mid 344.082237 -219.257515)
		(end 343.805764 -219.190316)
		(width 0.0889)
		(layer "In4.Cu")
		(net "DBP_CPU0_MBP1_GTL_R_N")
	)
	(arc
		(start 339.092032 -219.18168)
		(mid 338.904834 -219.131537)
		(end 338.717636 -219.18168)
		(width 0.0889)
		(layer "In4.Cu")
		(net "DBP_CPU0_MBP1_GTL_R_N")
	)
	(arc
		(start 356.489508 -227.9777)
		(mid 356.460312 -227.943803)
		(end 356.436676 -227.905818)
		(width 0.0889)
		(layer "In4.Cu")
		(net "DBP_CPU0_MBP1_GTL_R_N")
	)
	(arc
		(start 355.614732 -224.936304)
		(mid 355.485027 -224.849638)
		(end 355.33203 -224.81921)
		(width 0.0889)
		(layer "In4.Cu")
		(net "DBP_CPU0_MBP1_GTL_R_N")
	)
	(arc
		(start 338.152232 -219.18168)
		(mid 337.965034 -219.131537)
		(end 337.777836 -219.18168)
		(width 0.0889)
		(layer "In4.Cu")
		(net "DBP_CPU0_MBP1_GTL_R_N")
	)
	(arc
		(start 351.394268 -223.257364)
		(mid 351.11609 -223.327056)
		(end 350.839532 -223.251268)
		(width 0.0889)
		(layer "In4.Cu")
		(net "DBP_CPU0_MBP1_GTL_R_N")
	)
	(arc
		(start 357.13543 -230.891842)
		(mid 357.08316 -230.709477)
		(end 356.948232 -230.57612)
		(width 0.0889)
		(layer "In4.Cu")
		(net "DBP_CPU0_MBP1_GTL_R_N")
	)
	(arc
		(start 340.971632 -219.18168)
		(mid 340.784434 -219.131537)
		(end 340.597236 -219.18168)
		(width 0.0889)
		(layer "In4.Cu")
		(net "DBP_CPU0_MBP1_GTL_R_N")
	)
	(arc
		(start 334.998314 -216.609422)
		(mid 334.956011 -216.596575)
		(end 334.920082 -216.570814)
		(width 0.0889)
		(layer "In4.Cu")
		(net "DBP_CPU0_MBP1_GTL_R_N")
	)
	(arc
		(start 336.92973 -218.683586)
		(mid 336.87746 -218.501221)
		(end 336.742532 -218.367864)
		(width 0.0889)
		(layer "In4.Cu")
		(net "DBP_CPU0_MBP1_GTL_R_N")
	)
	(arc
		(start 347.936058 -221.230444)
		(mid 347.929411 -221.209283)
		(end 347.925136 -221.187518)
		(width 0.0889)
		(layer "In4.Cu")
		(net "DBP_CPU0_MBP1_GTL_R_N")
	)
	(arc
		(start 346.014294 -219.53982)
		(mid 345.932965 -219.376053)
		(end 345.795854 -219.255086)
		(width 0.0889)
		(layer "In4.Cu")
		(net "DBP_CPU0_MBP1_GTL_R_N")
	)
	(arc
		(start 354.508054 -224.586546)
		(mid 354.370331 -224.399051)
		(end 354.295202 -224.178876)
		(width 0.0889)
		(layer "In4.Cu")
		(net "DBP_CPU0_MBP1_GTL_R_N")
	)
	(arc
		(start 356.942136 -230.572564)
		(mid 356.739549 -230.366213)
		(end 356.66553 -230.086662)
		(width 0.0889)
		(layer "In4.Cu")
		(net "DBP_CPU0_MBP1_GTL_R_N")
	)
	(arc
		(start 345.670632 -219.18168)
		(mid 345.483434 -219.131537)
		(end 345.296236 -219.18168)
		(width 0.0889)
		(layer "In4.Cu")
		(net "DBP_CPU0_MBP1_GTL_R_N")
	)
	(arc
		(start 334.815688 -216.46642)
		(mid 334.756097 -216.393808)
		(end 334.711802 -216.310972)
		(width 0.0889)
		(layer "In4.Cu")
		(net "DBP_CPU0_MBP1_GTL_R_N")
	)
	(arc
		(start 340.597236 -219.18168)
		(mid 340.323037 -219.257515)
		(end 340.046564 -219.190316)
		(width 0.0889)
		(layer "In4.Cu")
		(net "DBP_CPU0_MBP1_GTL_R_N")
	)
	(arc
		(start 336.460084 -217.878406)
		(mid 336.412405 -217.695506)
		(end 336.281522 -217.559128)
		(width 0.0889)
		(layer "In4.Cu")
		(net "DBP_CPU0_MBP1_GTL_R_N")
	)
	(arc
		(start 354.295202 -224.178876)
		(mid 354.279847 -224.119757)
		(end 354.255324 -224.063814)
		(width 0.0889)
		(layer "In4.Cu")
		(net "DBP_CPU0_MBP1_GTL_R_N")
	)
	(arc
		(start 344.730832 -219.18168)
		(mid 344.543634 -219.131537)
		(end 344.356436 -219.18168)
		(width 0.0889)
		(layer "In4.Cu")
		(net "DBP_CPU0_MBP1_GTL_R_N")
	)
	(arc
		(start 337.777836 -219.18168)
		(mid 337.503637 -219.257515)
		(end 337.227164 -219.190316)
		(width 0.0889)
		(layer "In4.Cu")
		(net "DBP_CPU0_MBP1_GTL_R_N")
	)
	(arc
		(start 336.272632 -217.554048)
		(mid 336.069151 -217.353244)
		(end 335.98993 -217.07856)
		(width 0.0889)
		(layer "In4.Cu")
		(net "DBP_CPU0_MBP1_GTL_R_N")
	)
	(arc
		(start 335.98993 -217.064336)
		(mid 335.888422 -216.807906)
		(end 335.638902 -216.690448)
		(width 0.0889)
		(layer "In4.Cu")
		(net "DBP_CPU0_MBP1_GTL_R_N")
	)
	(arc
		(start 342.476836 -219.18168)
		(mid 342.202637 -219.257515)
		(end 341.926164 -219.190316)
		(width 0.0889)
		(layer "In4.Cu")
		(net "DBP_CPU0_MBP1_GTL_R_N")
	)
	(arc
		(start 348.825566 -222.884238)
		(mid 348.772514 -222.80489)
		(end 348.753938 -222.711264)
		(width 0.0889)
		(layer "In4.Cu")
		(net "DBP_CPU0_MBP1_GTL_R_N")
	)
	(arc
		(start 341.911432 -219.18168)
		(mid 341.724234 -219.131537)
		(end 341.537036 -219.18168)
		(width 0.0889)
		(layer "In4.Cu")
		(net "DBP_CPU0_MBP1_GTL_R_N")
	)
	(arc
		(start 356.66553 -230.086662)
		(mid 356.598323 -229.748789)
		(end 356.406958 -229.46233)
		(width 0.0889)
		(layer "In4.Cu")
		(net "DBP_CPU0_MBP1_GTL_R_N")
	)
	(arc
		(start 353.784916 -223.34347)
		(mid 353.754091 -223.311)
		(end 353.717606 -223.28505)
		(width 0.0889)
		(layer "In4.Cu")
		(net "DBP_CPU0_MBP1_GTL_R_N")
	)
	(arc
		(start 353.658678 -223.251268)
		(mid 353.47148 -223.201125)
		(end 353.284282 -223.251268)
		(width 0.0889)
		(layer "In4.Cu")
		(net "DBP_CPU0_MBP1_GTL_R_N")
	)
	(arc
		(start 349.8342 -223.213422)
		(mid 349.697835 -223.156955)
		(end 349.551498 -223.13773)
		(width 0.0889)
		(layer "In4.Cu")
		(net "DBP_CPU0_MBP1_GTL_R_N")
	)
	(arc
		(start 350.839532 -223.251268)
		(mid 350.652334 -223.201125)
		(end 350.465136 -223.251268)
		(width 0.0889)
		(layer "In4.Cu")
		(net "DBP_CPU0_MBP1_GTL_R_N")
	)
	(arc
		(start 357.23068 -233.34218)
		(mid 357.159514 -232.945835)
		(end 357.135684 -232.543858)
		(width 0.0889)
		(layer "In4.Cu")
		(net "DBP_CPU0_MBP1_GTL_R_N")
	)
	(arc
		(start 356.239064 -225.865436)
		(mid 356.215777 -225.748182)
		(end 356.149402 -225.648774)
		(width 0.0889)
		(layer "In4.Cu")
		(net "DBP_CPU0_MBP1_GTL_R_N")
	)
	(arc
		(start 352.334322 -223.257364)
		(mid 352.05589 -223.327178)
		(end 351.779078 -223.251268)
		(width 0.0889)
		(layer "In4.Cu")
		(net "DBP_CPU0_MBP1_GTL_R_N")
	)
	(arc
		(start 347.915484 -221.11462)
		(mid 347.938551 -220.873846)
		(end 348.066106 -220.668342)
		(width 0.0889)
		(layer "In4.Cu")
		(net "DBP_CPU0_MBP1_GTL_R_N")
	)
	(arc
		(start 356.396036 -228.975666)
		(mid 356.411518 -228.933445)
		(end 356.438454 -228.897434)
		(width 0.0889)
		(layer "In4.Cu")
		(net "DBP_CPU0_MBP1_GTL_R_N")
	)
	(arc
		(start 348.193868 -221.738444)
		(mid 348.060157 -221.51727)
		(end 347.954854 -221.281244)
		(width 0.0889)
		(layer "In4.Cu")
		(net "DBP_CPU0_MBP1_GTL_R_N")
	)
	(arc
		(start 345.296236 -219.18168)
		(mid 345.022037 -219.257515)
		(end 344.745564 -219.190316)
		(width 0.0889)
		(layer "In4.Cu")
		(net "DBP_CPU0_MBP1_GTL_R_N")
	)
	(arc
		(start 356.572058 -228.76383)
		(mid 356.717774 -228.41204)
		(end 356.572058 -228.06025)
		(width 0.0889)
		(layer "In4.Cu")
		(net "DBP_CPU0_MBP1_GTL_R_N")
	)
	(arc
		(start 347.635068 -220.001592)
		(mid 347.35689 -220.071315)
		(end 347.080332 -219.995496)
		(width 0.0889)
		(layer "In4.Cu")
		(net "DBP_CPU0_MBP1_GTL_R_N")
	)
	(arc
		(start 354.974144 -224.81921)
		(mid 354.758454 -224.776307)
		(end 354.575618 -224.65411)
		(width 0.0889)
		(layer "In4.Cu")
		(net "DBP_CPU0_MBP1_GTL_R_N")
	)
	(arc
		(start 348.019878 -219.995496)
		(mid 347.83268 -219.945353)
		(end 347.645482 -219.995496)
		(width 0.0889)
		(layer "In4.Cu")
		(net "DBP_CPU0_MBP1_GTL_R_N")
	)
	(arc
		(start 353.273868 -223.257364)
		(mid 352.99569 -223.327056)
		(end 352.719132 -223.251268)
		(width 0.0889)
		(layer "In4.Cu")
		(net "DBP_CPU0_MBP1_GTL_R_N")
	)
	(segment
		(start 356.29088 -232.250234)
		(end 356.29088 -231.714548)
		(width 0.12954)
		(layer "F.Cu")
		(net "DBP_CPU0_MBP0_GTL_R_N")
	)
	(segment
		(start 356.291134 -232.250488)
		(end 356.29088 -232.250234)
		(width 0.12954)
		(layer "F.Cu")
		(net "DBP_CPU0_MBP0_GTL_R_N")
	)
	(via
		(at 332.72222 -200.622408)
		(size 0.508)
		(drill 0.254)
		(layers "F.Cu" "B.Cu")
		(net "DBP_CPU0_MBP0_GTL_R_N")
	)
	(via
		(at 356.29088 -231.714548)
		(size 0.4572)
		(drill 0.2032)
		(layers "F.Cu" "B.Cu")
		(net "DBP_CPU0_MBP0_GTL_R_N")
	)
	(via
		(at 333.813658 -195.79717)
		(size 0.6604)
		(drill 0.3302)
		(layers "F.Cu" "B.Cu")
		(net "DBP_CPU0_MBP0_GTL_R_N")
	)
	(segment
		(start 333.077058 -199.68591)
		(end 333.077058 -196.53377)
		(width 0.12954)
		(layer "B.Cu")
		(net "DBP_CPU0_MBP0_GTL_R_N")
	)
	(segment
		(start 332.72222 -200.622408)
		(end 332.70571 -200.58253)
		(width 0.12954)
		(layer "B.Cu")
		(net "DBP_CPU0_MBP0_GTL_R_N")
	)
	(segment
		(start 333.077058 -196.53377)
		(end 333.813658 -195.79717)
		(width 0.12954)
		(layer "B.Cu")
		(net "DBP_CPU0_MBP0_GTL_R_N")
	)
	(segment
		(start 334.341978 -195.26885)
		(end 334.341978 -191.22898)
		(width 0.12954)
		(layer "B.Cu")
		(net "DBP_CPU0_MBP0_GTL_R_N")
	)
	(segment
		(start 333.813658 -195.79717)
		(end 334.341978 -195.26885)
		(width 0.12954)
		(layer "B.Cu")
		(net "DBP_CPU0_MBP0_GTL_R_N")
	)
	(segment
		(start 332.70571 -200.58253)
		(end 333.077058 -199.68591)
		(width 0.12954)
		(layer "B.Cu")
		(net "DBP_CPU0_MBP0_GTL_R_N")
	)
	(segment
		(start 341.067136 -219.995496)
		(end 341.056722 -220.001592)
		(width 0.0889)
		(layer "In4.Cu")
		(net "DBP_CPU0_MBP0_GTL_R_N")
	)
	(segment
		(start 355.547168 -229.767384)
		(end 355.538278 -229.762304)
		(width 0.0889)
		(layer "In4.Cu")
		(net "DBP_CPU0_MBP0_GTL_R_N")
	)
	(segment
		(start 355.256084 -227.702872)
		(end 355.256084 -227.629466)
		(width 0.0889)
		(layer "In4.Cu")
		(net "DBP_CPU0_MBP0_GTL_R_N")
	)
	(segment
		(start 351.324164 -225.701606)
		(end 351.309432 -225.69297)
		(width 0.0889)
		(layer "In4.Cu")
		(net "DBP_CPU0_MBP0_GTL_R_N")
	)
	(segment
		(start 344.260932 -219.995242)
		(end 344.260678 -219.995496)
		(width 0.0889)
		(layer "In4.Cu")
		(net "DBP_CPU0_MBP0_GTL_R_N")
	)
	(segment
		(start 347.550232 -222.436944)
		(end 347.54185 -222.432118)
		(width 0.0889)
		(layer "In4.Cu")
		(net "DBP_CPU0_MBP0_GTL_R_N")
	)
	(segment
		(start 344.731086 -220.809312)
		(end 344.72499 -220.805756)
		(width 0.0889)
		(layer "In4.Cu")
		(net "DBP_CPU0_MBP0_GTL_R_N")
	)
	(segment
		(start 330.996798 -211.27339)
		(end 330.996798 -202.04811)
		(width 0.127)
		(layer "In4.Cu")
		(net "DBP_CPU0_MBP0_GTL_R_N")
	)
	(segment
		(start 347.560138 -222.442786)
		(end 347.550232 -222.436944)
		(width 0.0889)
		(layer "In4.Cu")
		(net "DBP_CPU0_MBP0_GTL_R_N")
	)
	(segment
		(start 346.14612 -221.626176)
		(end 346.140532 -221.623128)
		(width 0.0889)
		(layer "In4.Cu")
		(net "DBP_CPU0_MBP0_GTL_R_N")
	)
	(segment
		(start 348.498922 -224.070164)
		(end 348.490032 -224.06483)
		(width 0.0889)
		(layer "In4.Cu")
		(net "DBP_CPU0_MBP0_GTL_R_N")
	)
	(segment
		(start 349.908368 -224.88398)
		(end 349.899478 -224.8789)
		(width 0.0889)
		(layer "In4.Cu")
		(net "DBP_CPU0_MBP0_GTL_R_N")
	)
	(segment
		(start 345.774264 -221.618302)
		(end 345.765882 -221.623128)
		(width 0.0889)
		(layer "In4.Cu")
		(net "DBP_CPU0_MBP0_GTL_R_N")
	)
	(segment
		(start 354.948998 -228.437948)
		(end 354.948998 -228.331014)
		(width 0.0889)
		(layer "In4.Cu")
		(net "DBP_CPU0_MBP0_GTL_R_N")
	)
	(segment
		(start 350.384364 -225.701606)
		(end 350.369632 -225.69297)
		(width 0.0889)
		(layer "In4.Cu")
		(net "DBP_CPU0_MBP0_GTL_R_N")
	)
	(segment
		(start 334.439768 -218.65971)
		(end 334.141318 -218.65971)
		(width 0.0889)
		(layer "In4.Cu")
		(net "DBP_CPU0_MBP0_GTL_R_N")
	)
	(segment
		(start 332.895194 -218.141042)
		(end 331.870558 -215.667082)
		(width 0.127)
		(layer "In4.Cu")
		(net "DBP_CPU0_MBP0_GTL_R_N")
	)
	(segment
		(start 346.610432 -222.436944)
		(end 346.607638 -222.435166)
		(width 0.0889)
		(layer "In4.Cu")
		(net "DBP_CPU0_MBP0_GTL_R_N")
	)
	(segment
		(start 344.918538 -221.145608)
		(end 344.918538 -221.133924)
		(width 0.0889)
		(layer "In4.Cu")
		(net "DBP_CPU0_MBP0_GTL_R_N")
	)
	(segment
		(start 339.187536 -219.995496)
		(end 339.177122 -220.001592)
		(width 0.0889)
		(layer "In4.Cu")
		(net "DBP_CPU0_MBP0_GTL_R_N")
	)
	(segment
		(start 335.851246 -220.071188)
		(end 334.439768 -218.65971)
		(width 0.0889)
		(layer "In4.Cu")
		(net "DBP_CPU0_MBP0_GTL_R_N")
	)
	(segment
		(start 340.127082 -219.995496)
		(end 340.116668 -220.001592)
		(width 0.0889)
		(layer "In4.Cu")
		(net "DBP_CPU0_MBP0_GTL_R_N")
	)
	(segment
		(start 345.765882 -221.623128)
		(end 345.755468 -221.629224)
		(width 0.0889)
		(layer "In4.Cu")
		(net "DBP_CPU0_MBP0_GTL_R_N")
	)
	(segment
		(start 343.886282 -219.995496)
		(end 343.875868 -220.001592)
		(width 0.0889)
		(layer "In4.Cu")
		(net "DBP_CPU0_MBP0_GTL_R_N")
	)
	(segment
		(start 356.19563 -230.914702)
		(end 356.19563 -230.900478)
		(width 0.0889)
		(layer "In4.Cu")
		(net "DBP_CPU0_MBP0_GTL_R_N")
	)
	(segment
		(start 350.08693 -225.217482)
		(end 350.08693 -225.203258)
		(width 0.0889)
		(layer "In4.Cu")
		(net "DBP_CPU0_MBP0_GTL_R_N")
	)
	(segment
		(start 344.26652 -219.99829)
		(end 344.260932 -219.995242)
		(width 0.0889)
		(layer "In4.Cu")
		(net "DBP_CPU0_MBP0_GTL_R_N")
	)
	(segment
		(start 342.006682 -219.995496)
		(end 341.996268 -220.001592)
		(width 0.0889)
		(layer "In4.Cu")
		(net "DBP_CPU0_MBP0_GTL_R_N")
	)
	(segment
		(start 352.263964 -225.701606)
		(end 352.249232 -225.69297)
		(width 0.0889)
		(layer "In4.Cu")
		(net "DBP_CPU0_MBP0_GTL_R_N")
	)
	(segment
		(start 356.017068 -230.5812)
		(end 356.008178 -230.57612)
		(width 0.0889)
		(layer "In4.Cu")
		(net "DBP_CPU0_MBP0_GTL_R_N")
	)
	(segment
		(start 355.538278 -227.155502)
		(end 355.547168 -227.150422)
		(width 0.0889)
		(layer "In4.Cu")
		(net "DBP_CPU0_MBP0_GTL_R_N")
	)
	(segment
		(start 355.256084 -226.032822)
		(end 355.256084 -226.017328)
		(width 0.0889)
		(layer "In4.Cu")
		(net "DBP_CPU0_MBP0_GTL_R_N")
	)
	(segment
		(start 346.620846 -222.44304)
		(end 346.610432 -222.436944)
		(width 0.0889)
		(layer "In4.Cu")
		(net "DBP_CPU0_MBP0_GTL_R_N")
	)
	(segment
		(start 334.141318 -218.65971)
		(end 333.413862 -218.65971)
		(width 0.127)
		(layer "In4.Cu")
		(net "DBP_CPU0_MBP0_GTL_R_N")
	)
	(segment
		(start 348.02572 -223.254062)
		(end 348.020132 -223.251014)
		(width 0.0889)
		(layer "In4.Cu")
		(net "DBP_CPU0_MBP0_GTL_R_N")
	)
	(segment
		(start 332.421738 -200.622408)
		(end 332.72222 -200.622408)
		(width 0.127)
		(layer "In4.Cu")
		(net "DBP_CPU0_MBP0_GTL_R_N")
	)
	(segment
		(start 353.203764 -225.701606)
		(end 353.189032 -225.69297)
		(width 0.0889)
		(layer "In4.Cu")
		(net "DBP_CPU0_MBP0_GTL_R_N")
	)
	(segment
		(start 348.677484 -224.404936)
		(end 348.677484 -224.389442)
		(width 0.0889)
		(layer "In4.Cu")
		(net "DBP_CPU0_MBP0_GTL_R_N")
	)
	(segment
		(start 333.413862 -218.65971)
		(end 332.895194 -218.141042)
		(width 0.127)
		(layer "In4.Cu")
		(net "DBP_CPU0_MBP0_GTL_R_N")
	)
	(segment
		(start 354.143564 -225.701606)
		(end 354.128832 -225.69297)
		(width 0.0889)
		(layer "In4.Cu")
		(net "DBP_CPU0_MBP0_GTL_R_N")
	)
	(segment
		(start 342.946736 -219.995496)
		(end 342.936322 -220.001592)
		(width 0.0889)
		(layer "In4.Cu")
		(net "DBP_CPU0_MBP0_GTL_R_N")
	)
	(segment
		(start 355.72573 -230.096568)
		(end 355.72573 -230.086662)
		(width 0.0889)
		(layer "In4.Cu")
		(net "DBP_CPU0_MBP0_GTL_R_N")
	)
	(segment
		(start 355.547168 -226.511866)
		(end 355.538278 -226.506786)
		(width 0.0889)
		(layer "In4.Cu")
		(net "DBP_CPU0_MBP0_GTL_R_N")
	)
	(segment
		(start 331.870558 -215.667082)
		(end 330.996798 -211.27339)
		(width 0.127)
		(layer "In4.Cu")
		(net "DBP_CPU0_MBP0_GTL_R_N")
	)
	(segment
		(start 347.737938 -222.781114)
		(end 347.737938 -222.761556)
		(width 0.0889)
		(layer "In4.Cu")
		(net "DBP_CPU0_MBP0_GTL_R_N")
	)
	(segment
		(start 344.736674 -220.81236)
		(end 344.731086 -220.809312)
		(width 0.0889)
		(layer "In4.Cu")
		(net "DBP_CPU0_MBP0_GTL_R_N")
	)
	(segment
		(start 349.525082 -224.8789)
		(end 349.51035 -224.887536)
		(width 0.0889)
		(layer "In4.Cu")
		(net "DBP_CPU0_MBP0_GTL_R_N")
	)
	(segment
		(start 330.996798 -202.04811)
		(end 332.421738 -200.622408)
		(width 0.127)
		(layer "In4.Cu")
		(net "DBP_CPU0_MBP0_GTL_R_N")
	)
	(segment
		(start 338.247482 -219.995496)
		(end 338.237068 -220.001592)
		(width 0.0889)
		(layer "In4.Cu")
		(net "DBP_CPU0_MBP0_GTL_R_N")
	)
	(segment
		(start 348.490032 -224.06483)
		(end 348.47911 -224.05848)
		(width 0.0889)
		(layer "In4.Cu")
		(net "DBP_CPU0_MBP0_GTL_R_N")
	)
	(segment
		(start 355.077522 -225.69805)
		(end 355.068632 -225.69297)
		(width 0.0889)
		(layer "In4.Cu")
		(net "DBP_CPU0_MBP0_GTL_R_N")
	)
	(segment
		(start 336.085434 -220.071188)
		(end 335.851246 -220.071188)
		(width 0.0889)
		(layer "In4.Cu")
		(net "DBP_CPU0_MBP0_GTL_R_N")
	)
	(segment
		(start 355.256084 -229.28834)
		(end 355.256084 -229.257352)
		(width 0.0889)
		(layer "In4.Cu")
		(net "DBP_CPU0_MBP0_GTL_R_N")
	)
	(arc
		(start 350.935036 -225.69297)
		(mid 350.660807 -225.768895)
		(end 350.384364 -225.701606)
		(width 0.0889)
		(layer "In4.Cu")
		(net "DBP_CPU0_MBP0_GTL_R_N")
	)
	(arc
		(start 337.307936 -219.995496)
		(mid 337.025234 -220.071272)
		(end 336.742532 -219.995496)
		(width 0.0889)
		(layer "In4.Cu")
		(net "DBP_CPU0_MBP0_GTL_R_N")
	)
	(arc
		(start 345.200732 -221.623128)
		(mid 344.997007 -221.421379)
		(end 344.918538 -221.145608)
		(width 0.0889)
		(layer "In4.Cu")
		(net "DBP_CPU0_MBP0_GTL_R_N")
	)
	(arc
		(start 355.256084 -227.629466)
		(mid 355.335454 -227.355732)
		(end 355.538278 -227.155502)
		(width 0.0889)
		(layer "In4.Cu")
		(net "DBP_CPU0_MBP0_GTL_R_N")
	)
	(arc
		(start 339.561932 -219.995496)
		(mid 339.374734 -219.945353)
		(end 339.187536 -219.995496)
		(width 0.0889)
		(layer "In4.Cu")
		(net "DBP_CPU0_MBP0_GTL_R_N")
	)
	(arc
		(start 349.51035 -224.887536)
		(mid 349.233875 -224.954856)
		(end 348.959678 -224.8789)
		(width 0.0889)
		(layer "In4.Cu")
		(net "DBP_CPU0_MBP0_GTL_R_N")
	)
	(arc
		(start 344.448384 -220.319854)
		(mid 344.399764 -220.135147)
		(end 344.26652 -219.99829)
		(width 0.0889)
		(layer "In4.Cu")
		(net "DBP_CPU0_MBP0_GTL_R_N")
	)
	(arc
		(start 348.677484 -224.389442)
		(mid 348.629805 -224.206542)
		(end 348.498922 -224.070164)
		(width 0.0889)
		(layer "In4.Cu")
		(net "DBP_CPU0_MBP0_GTL_R_N")
	)
	(arc
		(start 355.256084 -229.257352)
		(mid 355.203431 -228.965615)
		(end 355.051614 -228.710998)
		(width 0.0889)
		(layer "In4.Cu")
		(net "DBP_CPU0_MBP0_GTL_R_N")
	)
	(arc
		(start 346.327984 -221.94774)
		(mid 346.279364 -221.763033)
		(end 346.14612 -221.626176)
		(width 0.0889)
		(layer "In4.Cu")
		(net "DBP_CPU0_MBP0_GTL_R_N")
	)
	(arc
		(start 355.152198 -227.95357)
		(mid 355.229053 -227.838549)
		(end 355.256084 -227.702872)
		(width 0.0889)
		(layer "In4.Cu")
		(net "DBP_CPU0_MBP0_GTL_R_N")
	)
	(arc
		(start 356.29088 -231.714548)
		(mid 356.219526 -231.317451)
		(end 356.19563 -230.914702)
		(width 0.0889)
		(layer "In4.Cu")
		(net "DBP_CPU0_MBP0_GTL_R_N")
	)
	(arc
		(start 354.948998 -228.331014)
		(mid 354.952903 -228.286487)
		(end 354.964746 -228.243384)
		(width 0.0889)
		(layer "In4.Cu")
		(net "DBP_CPU0_MBP0_GTL_R_N")
	)
	(arc
		(start 355.538278 -226.506786)
		(mid 355.335455 -226.306555)
		(end 355.256084 -226.032822)
		(width 0.0889)
		(layer "In4.Cu")
		(net "DBP_CPU0_MBP0_GTL_R_N")
	)
	(arc
		(start 344.918538 -221.133924)
		(mid 344.869918 -220.949217)
		(end 344.736674 -220.81236)
		(width 0.0889)
		(layer "In4.Cu")
		(net "DBP_CPU0_MBP0_GTL_R_N")
	)
	(arc
		(start 347.54185 -222.432118)
		(mid 347.358088 -222.386749)
		(end 347.175582 -222.436944)
		(width 0.0889)
		(layer "In4.Cu")
		(net "DBP_CPU0_MBP0_GTL_R_N")
	)
	(arc
		(start 353.754436 -225.69297)
		(mid 353.480207 -225.768895)
		(end 353.203764 -225.701606)
		(width 0.0889)
		(layer "In4.Cu")
		(net "DBP_CPU0_MBP0_GTL_R_N")
	)
	(arc
		(start 343.875868 -220.001592)
		(mid 343.59769 -220.071315)
		(end 343.321132 -219.995496)
		(width 0.0889)
		(layer "In4.Cu")
		(net "DBP_CPU0_MBP0_GTL_R_N")
	)
	(arc
		(start 346.140532 -221.623128)
		(mid 345.958027 -221.572924)
		(end 345.774264 -221.618302)
		(width 0.0889)
		(layer "In4.Cu")
		(net "DBP_CPU0_MBP0_GTL_R_N")
	)
	(arc
		(start 355.538278 -229.762304)
		(mid 355.335455 -229.562073)
		(end 355.256084 -229.28834)
		(width 0.0889)
		(layer "In4.Cu")
		(net "DBP_CPU0_MBP0_GTL_R_N")
	)
	(arc
		(start 338.237068 -220.001592)
		(mid 337.95889 -220.071315)
		(end 337.682332 -219.995496)
		(width 0.0889)
		(layer "In4.Cu")
		(net "DBP_CPU0_MBP0_GTL_R_N")
	)
	(arc
		(start 348.959678 -224.8789)
		(mid 348.756855 -224.678669)
		(end 348.677484 -224.404936)
		(width 0.0889)
		(layer "In4.Cu")
		(net "DBP_CPU0_MBP0_GTL_R_N")
	)
	(arc
		(start 341.996268 -220.001592)
		(mid 341.71809 -220.071315)
		(end 341.441532 -219.995496)
		(width 0.0889)
		(layer "In4.Cu")
		(net "DBP_CPU0_MBP0_GTL_R_N")
	)
	(arc
		(start 336.368136 -219.995496)
		(mid 336.231767 -220.051938)
		(end 336.085434 -220.071188)
		(width 0.0889)
		(layer "In4.Cu")
		(net "DBP_CPU0_MBP0_GTL_R_N")
	)
	(arc
		(start 341.056722 -220.001592)
		(mid 340.77829 -220.071438)
		(end 340.501478 -219.995496)
		(width 0.0889)
		(layer "In4.Cu")
		(net "DBP_CPU0_MBP0_GTL_R_N")
	)
	(arc
		(start 343.321132 -219.995496)
		(mid 343.133934 -219.945353)
		(end 342.946736 -219.995496)
		(width 0.0889)
		(layer "In4.Cu")
		(net "DBP_CPU0_MBP0_GTL_R_N")
	)
	(arc
		(start 351.309432 -225.69297)
		(mid 351.122234 -225.642827)
		(end 350.935036 -225.69297)
		(width 0.0889)
		(layer "In4.Cu")
		(net "DBP_CPU0_MBP0_GTL_R_N")
	)
	(arc
		(start 348.207584 -223.575626)
		(mid 348.158964 -223.390919)
		(end 348.02572 -223.254062)
		(width 0.0889)
		(layer "In4.Cu")
		(net "DBP_CPU0_MBP0_GTL_R_N")
	)
	(arc
		(start 352.249232 -225.69297)
		(mid 352.062034 -225.642827)
		(end 351.874836 -225.69297)
		(width 0.0889)
		(layer "In4.Cu")
		(net "DBP_CPU0_MBP0_GTL_R_N")
	)
	(arc
		(start 355.051614 -228.710998)
		(mid 354.975502 -228.583789)
		(end 354.948998 -228.437948)
		(width 0.0889)
		(layer "In4.Cu")
		(net "DBP_CPU0_MBP0_GTL_R_N")
	)
	(arc
		(start 353.189032 -225.69297)
		(mid 353.001834 -225.642827)
		(end 352.814636 -225.69297)
		(width 0.0889)
		(layer "In4.Cu")
		(net "DBP_CPU0_MBP0_GTL_R_N")
	)
	(arc
		(start 336.742532 -219.995496)
		(mid 336.555334 -219.945353)
		(end 336.368136 -219.995496)
		(width 0.0889)
		(layer "In4.Cu")
		(net "DBP_CPU0_MBP0_GTL_R_N")
	)
	(arc
		(start 339.177122 -220.001592)
		(mid 338.89869 -220.071438)
		(end 338.621878 -219.995496)
		(width 0.0889)
		(layer "In4.Cu")
		(net "DBP_CPU0_MBP0_GTL_R_N")
	)
	(arc
		(start 340.501478 -219.995496)
		(mid 340.31428 -219.945353)
		(end 340.127082 -219.995496)
		(width 0.0889)
		(layer "In4.Cu")
		(net "DBP_CPU0_MBP0_GTL_R_N")
	)
	(arc
		(start 348.020132 -223.251014)
		(mid 347.818265 -223.052559)
		(end 347.737938 -222.781114)
		(width 0.0889)
		(layer "In4.Cu")
		(net "DBP_CPU0_MBP0_GTL_R_N")
	)
	(arc
		(start 355.068632 -225.69297)
		(mid 354.881434 -225.642827)
		(end 354.694236 -225.69297)
		(width 0.0889)
		(layer "In4.Cu")
		(net "DBP_CPU0_MBP0_GTL_R_N")
	)
	(arc
		(start 340.116668 -220.001592)
		(mid 339.83849 -220.071315)
		(end 339.561932 -219.995496)
		(width 0.0889)
		(layer "In4.Cu")
		(net "DBP_CPU0_MBP0_GTL_R_N")
	)
	(arc
		(start 352.814636 -225.69297)
		(mid 352.540407 -225.768895)
		(end 352.263964 -225.701606)
		(width 0.0889)
		(layer "In4.Cu")
		(net "DBP_CPU0_MBP0_GTL_R_N")
	)
	(arc
		(start 355.72573 -230.086662)
		(mid 355.678051 -229.903762)
		(end 355.547168 -229.767384)
		(width 0.0889)
		(layer "In4.Cu")
		(net "DBP_CPU0_MBP0_GTL_R_N")
	)
	(arc
		(start 337.682332 -219.995496)
		(mid 337.495134 -219.945353)
		(end 337.307936 -219.995496)
		(width 0.0889)
		(layer "In4.Cu")
		(net "DBP_CPU0_MBP0_GTL_R_N")
	)
	(arc
		(start 346.607638 -222.435166)
		(mid 346.402874 -222.228712)
		(end 346.327984 -221.94774)
		(width 0.0889)
		(layer "In4.Cu")
		(net "DBP_CPU0_MBP0_GTL_R_N")
	)
	(arc
		(start 347.175582 -222.436944)
		(mid 346.899023 -222.512721)
		(end 346.620846 -222.44304)
		(width 0.0889)
		(layer "In4.Cu")
		(net "DBP_CPU0_MBP0_GTL_R_N")
	)
	(arc
		(start 348.47911 -224.05848)
		(mid 348.280141 -223.8526)
		(end 348.207584 -223.575626)
		(width 0.0889)
		(layer "In4.Cu")
		(net "DBP_CPU0_MBP0_GTL_R_N")
	)
	(arc
		(start 342.936322 -220.001592)
		(mid 342.65789 -220.071438)
		(end 342.381078 -219.995496)
		(width 0.0889)
		(layer "In4.Cu")
		(net "DBP_CPU0_MBP0_GTL_R_N")
	)
	(arc
		(start 356.008178 -230.57612)
		(mid 355.803843 -230.373515)
		(end 355.72573 -230.096568)
		(width 0.0889)
		(layer "In4.Cu")
		(net "DBP_CPU0_MBP0_GTL_R_N")
	)
	(arc
		(start 342.381078 -219.995496)
		(mid 342.19388 -219.945353)
		(end 342.006682 -219.995496)
		(width 0.0889)
		(layer "In4.Cu")
		(net "DBP_CPU0_MBP0_GTL_R_N")
	)
	(arc
		(start 354.694236 -225.69297)
		(mid 354.420007 -225.768895)
		(end 354.143564 -225.701606)
		(width 0.0889)
		(layer "In4.Cu")
		(net "DBP_CPU0_MBP0_GTL_R_N")
	)
	(arc
		(start 344.260678 -219.995496)
		(mid 344.07348 -219.945353)
		(end 343.886282 -219.995496)
		(width 0.0889)
		(layer "In4.Cu")
		(net "DBP_CPU0_MBP0_GTL_R_N")
	)
	(arc
		(start 355.256084 -226.017328)
		(mid 355.208405 -225.834428)
		(end 355.077522 -225.69805)
		(width 0.0889)
		(layer "In4.Cu")
		(net "DBP_CPU0_MBP0_GTL_R_N")
	)
	(arc
		(start 356.19563 -230.900478)
		(mid 356.147951 -230.717578)
		(end 356.017068 -230.5812)
		(width 0.0889)
		(layer "In4.Cu")
		(net "DBP_CPU0_MBP0_GTL_R_N")
	)
	(arc
		(start 345.755468 -221.629224)
		(mid 345.47729 -221.698979)
		(end 345.200732 -221.623128)
		(width 0.0889)
		(layer "In4.Cu")
		(net "DBP_CPU0_MBP0_GTL_R_N")
	)
	(arc
		(start 354.964746 -228.243384)
		(mid 355.04305 -228.088501)
		(end 355.152198 -227.95357)
		(width 0.0889)
		(layer "In4.Cu")
		(net "DBP_CPU0_MBP0_GTL_R_N")
	)
	(arc
		(start 349.899478 -224.8789)
		(mid 349.71228 -224.828757)
		(end 349.525082 -224.8789)
		(width 0.0889)
		(layer "In4.Cu")
		(net "DBP_CPU0_MBP0_GTL_R_N")
	)
	(arc
		(start 347.737938 -222.761556)
		(mid 347.690482 -222.579055)
		(end 347.560138 -222.442786)
		(width 0.0889)
		(layer "In4.Cu")
		(net "DBP_CPU0_MBP0_GTL_R_N")
	)
	(arc
		(start 341.441532 -219.995496)
		(mid 341.254334 -219.945353)
		(end 341.067136 -219.995496)
		(width 0.0889)
		(layer "In4.Cu")
		(net "DBP_CPU0_MBP0_GTL_R_N")
	)
	(arc
		(start 344.72499 -220.805756)
		(mid 344.522403 -220.599405)
		(end 344.448384 -220.319854)
		(width 0.0889)
		(layer "In4.Cu")
		(net "DBP_CPU0_MBP0_GTL_R_N")
	)
	(arc
		(start 355.547168 -227.150422)
		(mid 355.725765 -226.831144)
		(end 355.547168 -226.511866)
		(width 0.0889)
		(layer "In4.Cu")
		(net "DBP_CPU0_MBP0_GTL_R_N")
	)
	(arc
		(start 350.08693 -225.203258)
		(mid 350.039251 -225.020358)
		(end 349.908368 -224.88398)
		(width 0.0889)
		(layer "In4.Cu")
		(net "DBP_CPU0_MBP0_GTL_R_N")
	)
	(arc
		(start 354.128832 -225.69297)
		(mid 353.941634 -225.642827)
		(end 353.754436 -225.69297)
		(width 0.0889)
		(layer "In4.Cu")
		(net "DBP_CPU0_MBP0_GTL_R_N")
	)
	(arc
		(start 350.369632 -225.69297)
		(mid 350.166151 -225.492166)
		(end 350.08693 -225.217482)
		(width 0.0889)
		(layer "In4.Cu")
		(net "DBP_CPU0_MBP0_GTL_R_N")
	)
	(arc
		(start 351.874836 -225.69297)
		(mid 351.600607 -225.768895)
		(end 351.324164 -225.701606)
		(width 0.0889)
		(layer "In4.Cu")
		(net "DBP_CPU0_MBP0_GTL_R_N")
	)
	(arc
		(start 338.621878 -219.995496)
		(mid 338.43468 -219.945353)
		(end 338.247482 -219.995496)
		(width 0.0889)
		(layer "In4.Cu")
		(net "DBP_CPU0_MBP0_GTL_R_N")
	)
	(segment
		(start 355.821234 -233.06405)
		(end 355.821234 -232.528364)
		(width 0.12954)
		(layer "F.Cu")
		(net "DBP_CPU0_HOOK9_MBP3_GTL_QS_R_N")
	)
	(segment
		(start 355.82098 -233.064304)
		(end 355.821234 -233.06405)
		(width 0.12954)
		(layer "F.Cu")
		(net "DBP_CPU0_HOOK9_MBP3_GTL_QS_R_N")
	)
	(via
		(at 332.097126 -200.094088)
		(size 0.508)
		(drill 0.254)
		(layers "F.Cu" "B.Cu")
		(net "DBP_CPU0_HOOK9_MBP3_GTL_QS_R_N")
	)
	(via
		(at 355.821234 -232.528364)
		(size 0.4572)
		(drill 0.2032)
		(layers "F.Cu" "B.Cu")
		(net "DBP_CPU0_HOOK9_MBP3_GTL_QS_R_N")
	)
	(via
		(at 332.137258 -194.24269)
		(size 0.6604)
		(drill 0.3302)
		(layers "F.Cu" "B.Cu")
		(net "DBP_CPU0_HOOK9_MBP3_GTL_QS_R_N")
	)
	(segment
		(start 332.097126 -200.094088)
		(end 332.097126 -199.992742)
		(width 0.12954)
		(layer "B.Cu")
		(net "DBP_CPU0_HOOK9_MBP3_GTL_QS_R_N")
	)
	(segment
		(start 331.969618 -196.81063)
		(end 332.137258 -196.64299)
		(width 0.12954)
		(layer "B.Cu")
		(net "DBP_CPU0_HOOK9_MBP3_GTL_QS_R_N")
	)
	(segment
		(start 332.137258 -194.24269)
		(end 332.137258 -192.41897)
		(width 0.12954)
		(layer "B.Cu")
		(net "DBP_CPU0_HOOK9_MBP3_GTL_QS_R_N")
	)
	(segment
		(start 332.137258 -192.41897)
		(end 332.447138 -192.10909)
		(width 0.12954)
		(layer "B.Cu")
		(net "DBP_CPU0_HOOK9_MBP3_GTL_QS_R_N")
	)
	(segment
		(start 332.097126 -199.992742)
		(end 332.238858 -199.85101)
		(width 0.12954)
		(layer "B.Cu")
		(net "DBP_CPU0_HOOK9_MBP3_GTL_QS_R_N")
	)
	(segment
		(start 332.137258 -196.64299)
		(end 332.137258 -194.24269)
		(width 0.12954)
		(layer "B.Cu")
		(net "DBP_CPU0_HOOK9_MBP3_GTL_QS_R_N")
	)
	(segment
		(start 332.238858 -199.29475)
		(end 331.969618 -199.02551)
		(width 0.12954)
		(layer "B.Cu")
		(net "DBP_CPU0_HOOK9_MBP3_GTL_QS_R_N")
	)
	(segment
		(start 331.969618 -199.02551)
		(end 331.969618 -196.81063)
		(width 0.12954)
		(layer "B.Cu")
		(net "DBP_CPU0_HOOK9_MBP3_GTL_QS_R_N")
	)
	(segment
		(start 332.447138 -192.10909)
		(end 332.447138 -191.22898)
		(width 0.12954)
		(layer "B.Cu")
		(net "DBP_CPU0_HOOK9_MBP3_GTL_QS_R_N")
	)
	(segment
		(start 332.238858 -199.85101)
		(end 332.238858 -199.29475)
		(width 0.12954)
		(layer "B.Cu")
		(net "DBP_CPU0_HOOK9_MBP3_GTL_QS_R_N")
	)
	(segment
		(start 346.705936 -223.899984)
		(end 346.697046 -223.894904)
		(width 0.0889)
		(layer "In4.Cu")
		(net "DBP_CPU0_HOOK9_MBP3_GTL_QS_R_N")
	)
	(segment
		(start 341.066882 -222.272098)
		(end 341.05215 -222.263462)
		(width 0.0889)
		(layer "In4.Cu")
		(net "DBP_CPU0_HOOK9_MBP3_GTL_QS_R_N")
	)
	(segment
		(start 332.097126 -200.310242)
		(end 332.097126 -200.094088)
		(width 0.127)
		(layer "In4.Cu")
		(net "DBP_CPU0_HOOK9_MBP3_GTL_QS_R_N")
	)
	(segment
		(start 346.988384 -224.389442)
		(end 346.988384 -224.379536)
		(width 0.0889)
		(layer "In4.Cu")
		(net "DBP_CPU0_HOOK9_MBP3_GTL_QS_R_N")
	)
	(segment
		(start 347.45803 -225.203258)
		(end 347.45803 -225.187764)
		(width 0.0889)
		(layer "In4.Cu")
		(net "DBP_CPU0_HOOK9_MBP3_GTL_QS_R_N")
	)
	(segment
		(start 354.976684 -230.095298)
		(end 354.976684 -230.076756)
		(width 0.0889)
		(layer "In4.Cu")
		(net "DBP_CPU0_HOOK9_MBP3_GTL_QS_R_N")
	)
	(segment
		(start 348.585282 -225.527616)
		(end 348.57055 -225.51898)
		(width 0.0889)
		(layer "In4.Cu")
		(net "DBP_CPU0_HOOK9_MBP3_GTL_QS_R_N")
	)
	(segment
		(start 344.826082 -222.272098)
		(end 344.81135 -222.263462)
		(width 0.0889)
		(layer "In4.Cu")
		(net "DBP_CPU0_HOOK9_MBP3_GTL_QS_R_N")
	)
	(segment
		(start 339.187282 -222.272098)
		(end 339.178392 -222.267018)
		(width 0.0889)
		(layer "In4.Cu")
		(net "DBP_CPU0_HOOK9_MBP3_GTL_QS_R_N")
	)
	(segment
		(start 352.344736 -227.155502)
		(end 352.335846 -227.150422)
		(width 0.0889)
		(layer "In4.Cu")
		(net "DBP_CPU0_HOOK9_MBP3_GTL_QS_R_N")
	)
	(segment
		(start 355.66477 -232.257346)
		(end 355.6889 -232.168192)
		(width 0.0889)
		(layer "In4.Cu")
		(net "DBP_CPU0_HOOK9_MBP3_GTL_QS_R_N")
	)
	(segment
		(start 346.048584 -222.761556)
		(end 346.048584 -222.752666)
		(width 0.0889)
		(layer "In4.Cu")
		(net "DBP_CPU0_HOOK9_MBP3_GTL_QS_R_N")
	)
	(segment
		(start 352.157284 -226.831144)
		(end 352.157284 -226.821238)
		(width 0.0889)
		(layer "In4.Cu")
		(net "DBP_CPU0_HOOK9_MBP3_GTL_QS_R_N")
	)
	(segment
		(start 354.03663 -228.45903)
		(end 354.03663 -228.436932)
		(width 0.0889)
		(layer "In4.Cu")
		(net "DBP_CPU0_HOOK9_MBP3_GTL_QS_R_N")
	)
	(segment
		(start 352.627184 -227.64496)
		(end 352.627184 -227.635054)
		(width 0.0889)
		(layer "In4.Cu")
		(net "DBP_CPU0_HOOK9_MBP3_GTL_QS_R_N")
	)
	(segment
		(start 355.821234 -232.528364)
		(end 355.66477 -232.257346)
		(width 0.0889)
		(layer "In4.Cu")
		(net "DBP_CPU0_HOOK9_MBP3_GTL_QS_R_N")
	)
	(segment
		(start 355.91623 -231.730042)
		(end 355.91623 -231.696006)
		(width 0.0889)
		(layer "In4.Cu")
		(net "DBP_CPU0_HOOK9_MBP3_GTL_QS_R_N")
	)
	(segment
		(start 349.525082 -225.527616)
		(end 349.51035 -225.51898)
		(width 0.0889)
		(layer "In4.Cu")
		(net "DBP_CPU0_HOOK9_MBP3_GTL_QS_R_N")
	)
	(segment
		(start 352.814636 -227.969318)
		(end 352.805746 -227.964238)
		(width 0.0889)
		(layer "In4.Cu")
		(net "DBP_CPU0_HOOK9_MBP3_GTL_QS_R_N")
	)
	(segment
		(start 345.904058 -222.40367)
		(end 345.859354 -222.358966)
		(width 0.0889)
		(layer "In4.Cu")
		(net "DBP_CPU0_HOOK9_MBP3_GTL_QS_R_N")
	)
	(segment
		(start 349.995236 -226.341686)
		(end 349.986346 -226.336606)
		(width 0.0889)
		(layer "In4.Cu")
		(net "DBP_CPU0_HOOK9_MBP3_GTL_QS_R_N")
	)
	(segment
		(start 337.590384 -221.133924)
		(end 337.590384 -221.115382)
		(width 0.0889)
		(layer "In4.Cu")
		(net "DBP_CPU0_HOOK9_MBP3_GTL_QS_R_N")
	)
	(segment
		(start 343.886282 -222.272098)
		(end 343.87155 -222.263462)
		(width 0.0889)
		(layer "In4.Cu")
		(net "DBP_CPU0_HOOK9_MBP3_GTL_QS_R_N")
	)
	(segment
		(start 346.518484 -223.575626)
		(end 346.518484 -223.561402)
		(width 0.0889)
		(layer "In4.Cu")
		(net "DBP_CPU0_HOOK9_MBP3_GTL_QS_R_N")
	)
	(segment
		(start 347.175836 -224.7138)
		(end 347.166946 -224.70872)
		(width 0.0889)
		(layer "In4.Cu")
		(net "DBP_CPU0_HOOK9_MBP3_GTL_QS_R_N")
	)
	(segment
		(start 342.006682 -222.272098)
		(end 341.99195 -222.263462)
		(width 0.0889)
		(layer "In4.Cu")
		(net "DBP_CPU0_HOOK9_MBP3_GTL_QS_R_N")
	)
	(segment
		(start 334.52054 -219.244672)
		(end 334.255618 -219.244672)
		(width 0.0889)
		(layer "In4.Cu")
		(net "DBP_CPU0_HOOK9_MBP3_GTL_QS_R_N")
	)
	(segment
		(start 346.236036 -223.085914)
		(end 346.227146 -223.080834)
		(width 0.0889)
		(layer "In4.Cu")
		(net "DBP_CPU0_HOOK9_MBP3_GTL_QS_R_N")
	)
	(segment
		(start 330.506578 -201.90079)
		(end 332.097126 -200.310242)
		(width 0.127)
		(layer "In4.Cu")
		(net "DBP_CPU0_HOOK9_MBP3_GTL_QS_R_N")
	)
	(segment
		(start 353.203764 -227.960682)
		(end 353.189032 -227.969318)
		(width 0.0889)
		(layer "In4.Cu")
		(net "DBP_CPU0_HOOK9_MBP3_GTL_QS_R_N")
	)
	(segment
		(start 355.169978 -230.414576)
		(end 355.163882 -230.41102)
		(width 0.0889)
		(layer "In4.Cu")
		(net "DBP_CPU0_HOOK9_MBP3_GTL_QS_R_N")
	)
	(segment
		(start 334.255618 -219.244672)
		(end 333.386684 -219.244672)
		(width 0.127)
		(layer "In4.Cu")
		(net "DBP_CPU0_HOOK9_MBP3_GTL_QS_R_N")
	)
	(segment
		(start 354.224082 -228.783388)
		(end 354.215192 -228.778308)
		(width 0.0889)
		(layer "In4.Cu")
		(net "DBP_CPU0_HOOK9_MBP3_GTL_QS_R_N")
	)
	(segment
		(start 350.384364 -226.33305)
		(end 350.369632 -226.341686)
		(width 0.0889)
		(layer "In4.Cu")
		(net "DBP_CPU0_HOOK9_MBP3_GTL_QS_R_N")
	)
	(segment
		(start 338.166964 -221.449646)
		(end 338.152232 -221.458282)
		(width 0.0889)
		(layer "In4.Cu")
		(net "DBP_CPU0_HOOK9_MBP3_GTL_QS_R_N")
	)
	(segment
		(start 335.518252 -220.242384)
		(end 334.52054 -219.244672)
		(width 0.0889)
		(layer "In4.Cu")
		(net "DBP_CPU0_HOOK9_MBP3_GTL_QS_R_N")
	)
	(segment
		(start 342.946482 -222.272098)
		(end 342.93175 -222.263462)
		(width 0.0889)
		(layer "In4.Cu")
		(net "DBP_CPU0_HOOK9_MBP3_GTL_QS_R_N")
	)
	(segment
		(start 349.807784 -226.017328)
		(end 349.807784 -226.003104)
		(width 0.0889)
		(layer "In4.Cu")
		(net "DBP_CPU0_HOOK9_MBP3_GTL_QS_R_N")
	)
	(segment
		(start 340.127082 -222.272098)
		(end 340.11235 -222.263462)
		(width 0.0889)
		(layer "In4.Cu")
		(net "DBP_CPU0_HOOK9_MBP3_GTL_QS_R_N")
	)
	(segment
		(start 355.446584 -230.909114)
		(end 355.446584 -230.900478)
		(width 0.0889)
		(layer "In4.Cu")
		(net "DBP_CPU0_HOOK9_MBP3_GTL_QS_R_N")
	)
	(segment
		(start 347.645482 -225.527616)
		(end 347.636592 -225.522536)
		(width 0.0889)
		(layer "In4.Cu")
		(net "DBP_CPU0_HOOK9_MBP3_GTL_QS_R_N")
	)
	(segment
		(start 354.506784 -229.272846)
		(end 354.506784 -229.27056)
		(width 0.0889)
		(layer "In4.Cu")
		(net "DBP_CPU0_HOOK9_MBP3_GTL_QS_R_N")
	)
	(segment
		(start 337.777836 -221.458282)
		(end 337.768946 -221.453202)
		(width 0.0889)
		(layer "In4.Cu")
		(net "DBP_CPU0_HOOK9_MBP3_GTL_QS_R_N")
	)
	(segment
		(start 338.99983 -221.94774)
		(end 338.99983 -221.932246)
		(width 0.0889)
		(layer "In4.Cu")
		(net "DBP_CPU0_HOOK9_MBP3_GTL_QS_R_N")
	)
	(segment
		(start 333.386684 -219.244672)
		(end 330.506578 -216.364566)
		(width 0.127)
		(layer "In4.Cu")
		(net "DBP_CPU0_HOOK9_MBP3_GTL_QS_R_N")
	)
	(segment
		(start 330.506578 -216.364566)
		(end 330.506578 -201.90079)
		(width 0.127)
		(layer "In4.Cu")
		(net "DBP_CPU0_HOOK9_MBP3_GTL_QS_R_N")
	)
	(segment
		(start 354.694236 -229.597204)
		(end 354.685346 -229.592124)
		(width 0.0889)
		(layer "In4.Cu")
		(net "DBP_CPU0_HOOK9_MBP3_GTL_QS_R_N")
	)
	(arc
		(start 349.807784 -226.003104)
		(mid 349.728565 -225.728419)
		(end 349.525082 -225.527616)
		(width 0.0889)
		(layer "In4.Cu")
		(net "DBP_CPU0_HOOK9_MBP3_GTL_QS_R_N")
	)
	(arc
		(start 348.57055 -225.51898)
		(mid 348.294109 -225.451814)
		(end 348.019878 -225.527616)
		(width 0.0889)
		(layer "In4.Cu")
		(net "DBP_CPU0_HOOK9_MBP3_GTL_QS_R_N")
	)
	(arc
		(start 354.506784 -229.27056)
		(mid 354.430987 -228.988936)
		(end 354.224082 -228.783388)
		(width 0.0889)
		(layer "In4.Cu")
		(net "DBP_CPU0_HOOK9_MBP3_GTL_QS_R_N")
	)
	(arc
		(start 345.200478 -222.272098)
		(mid 345.01328 -222.322241)
		(end 344.826082 -222.272098)
		(width 0.0889)
		(layer "In4.Cu")
		(net "DBP_CPU0_HOOK9_MBP3_GTL_QS_R_N")
	)
	(arc
		(start 349.51035 -225.51898)
		(mid 349.233909 -225.451814)
		(end 348.959678 -225.527616)
		(width 0.0889)
		(layer "In4.Cu")
		(net "DBP_CPU0_HOOK9_MBP3_GTL_QS_R_N")
	)
	(arc
		(start 341.441278 -222.272098)
		(mid 341.25408 -222.322241)
		(end 341.066882 -222.272098)
		(width 0.0889)
		(layer "In4.Cu")
		(net "DBP_CPU0_HOOK9_MBP3_GTL_QS_R_N")
	)
	(arc
		(start 336.050128 -220.525086)
		(mid 335.763057 -220.423491)
		(end 335.518252 -220.242384)
		(width 0.0889)
		(layer "In4.Cu")
		(net "DBP_CPU0_HOOK9_MBP3_GTL_QS_R_N")
	)
	(arc
		(start 346.697046 -223.894904)
		(mid 346.566132 -223.758544)
		(end 346.518484 -223.575626)
		(width 0.0889)
		(layer "In4.Cu")
		(net "DBP_CPU0_HOOK9_MBP3_GTL_QS_R_N")
	)
	(arc
		(start 353.189032 -227.969318)
		(mid 353.001834 -228.019461)
		(end 352.814636 -227.969318)
		(width 0.0889)
		(layer "In4.Cu")
		(net "DBP_CPU0_HOOK9_MBP3_GTL_QS_R_N")
	)
	(arc
		(start 352.627184 -227.635054)
		(mid 352.549073 -227.358105)
		(end 352.344736 -227.155502)
		(width 0.0889)
		(layer "In4.Cu")
		(net "DBP_CPU0_HOOK9_MBP3_GTL_QS_R_N")
	)
	(arc
		(start 337.590384 -221.115382)
		(mid 337.510222 -220.843193)
		(end 337.307936 -220.644212)
		(width 0.0889)
		(layer "In4.Cu")
		(net "DBP_CPU0_HOOK9_MBP3_GTL_QS_R_N")
	)
	(arc
		(start 355.163882 -230.41102)
		(mid 355.028949 -230.277666)
		(end 354.976684 -230.095298)
		(width 0.0889)
		(layer "In4.Cu")
		(net "DBP_CPU0_HOOK9_MBP3_GTL_QS_R_N")
	)
	(arc
		(start 345.859354 -222.358966)
		(mid 345.544656 -222.20366)
		(end 345.200478 -222.272098)
		(width 0.0889)
		(layer "In4.Cu")
		(net "DBP_CPU0_HOOK9_MBP3_GTL_QS_R_N")
	)
	(arc
		(start 350.935036 -226.341686)
		(mid 350.660837 -226.265851)
		(end 350.384364 -226.33305)
		(width 0.0889)
		(layer "In4.Cu")
		(net "DBP_CPU0_HOOK9_MBP3_GTL_QS_R_N")
	)
	(arc
		(start 346.048584 -222.752666)
		(mid 346.011017 -222.563803)
		(end 345.904058 -222.40367)
		(width 0.0889)
		(layer "In4.Cu")
		(net "DBP_CPU0_HOOK9_MBP3_GTL_QS_R_N")
	)
	(arc
		(start 350.369632 -226.341686)
		(mid 350.182434 -226.391829)
		(end 349.995236 -226.341686)
		(width 0.0889)
		(layer "In4.Cu")
		(net "DBP_CPU0_HOOK9_MBP3_GTL_QS_R_N")
	)
	(arc
		(start 338.152232 -221.458282)
		(mid 337.965034 -221.508425)
		(end 337.777836 -221.458282)
		(width 0.0889)
		(layer "In4.Cu")
		(net "DBP_CPU0_HOOK9_MBP3_GTL_QS_R_N")
	)
	(arc
		(start 337.307936 -220.644212)
		(mid 337.025234 -220.56847)
		(end 336.742532 -220.644212)
		(width 0.0889)
		(layer "In4.Cu")
		(net "DBP_CPU0_HOOK9_MBP3_GTL_QS_R_N")
	)
	(arc
		(start 339.178392 -222.267018)
		(mid 339.047478 -222.130658)
		(end 338.99983 -221.94774)
		(width 0.0889)
		(layer "In4.Cu")
		(net "DBP_CPU0_HOOK9_MBP3_GTL_QS_R_N")
	)
	(arc
		(start 338.99983 -221.932246)
		(mid 338.92046 -221.658512)
		(end 338.717636 -221.458282)
		(width 0.0889)
		(layer "In4.Cu")
		(net "DBP_CPU0_HOOK9_MBP3_GTL_QS_R_N")
	)
	(arc
		(start 348.019878 -225.527616)
		(mid 347.83268 -225.577759)
		(end 347.645482 -225.527616)
		(width 0.0889)
		(layer "In4.Cu")
		(net "DBP_CPU0_HOOK9_MBP3_GTL_QS_R_N")
	)
	(arc
		(start 352.805746 -227.964238)
		(mid 352.674832 -227.827878)
		(end 352.627184 -227.64496)
		(width 0.0889)
		(layer "In4.Cu")
		(net "DBP_CPU0_HOOK9_MBP3_GTL_QS_R_N")
	)
	(arc
		(start 346.518484 -223.561402)
		(mid 346.439343 -223.286779)
		(end 346.236036 -223.085914)
		(width 0.0889)
		(layer "In4.Cu")
		(net "DBP_CPU0_HOOK9_MBP3_GTL_QS_R_N")
	)
	(arc
		(start 354.976684 -230.076756)
		(mid 354.898573 -229.799807)
		(end 354.694236 -229.597204)
		(width 0.0889)
		(layer "In4.Cu")
		(net "DBP_CPU0_HOOK9_MBP3_GTL_QS_R_N")
	)
	(arc
		(start 336.742532 -220.644212)
		(mid 336.555334 -220.694355)
		(end 336.368136 -220.644212)
		(width 0.0889)
		(layer "In4.Cu")
		(net "DBP_CPU0_HOOK9_MBP3_GTL_QS_R_N")
	)
	(arc
		(start 351.309432 -226.341686)
		(mid 351.122234 -226.391829)
		(end 350.935036 -226.341686)
		(width 0.0889)
		(layer "In4.Cu")
		(net "DBP_CPU0_HOOK9_MBP3_GTL_QS_R_N")
	)
	(arc
		(start 355.633782 -231.224836)
		(mid 355.498849 -231.091482)
		(end 355.446584 -230.909114)
		(width 0.0889)
		(layer "In4.Cu")
		(net "DBP_CPU0_HOOK9_MBP3_GTL_QS_R_N")
	)
	(arc
		(start 338.717636 -221.458282)
		(mid 338.443437 -221.382447)
		(end 338.166964 -221.449646)
		(width 0.0889)
		(layer "In4.Cu")
		(net "DBP_CPU0_HOOK9_MBP3_GTL_QS_R_N")
	)
	(arc
		(start 353.754436 -227.969318)
		(mid 353.480207 -227.893393)
		(end 353.203764 -227.960682)
		(width 0.0889)
		(layer "In4.Cu")
		(net "DBP_CPU0_HOOK9_MBP3_GTL_QS_R_N")
	)
	(arc
		(start 342.93175 -222.263462)
		(mid 342.655275 -222.196142)
		(end 342.381078 -222.272098)
		(width 0.0889)
		(layer "In4.Cu")
		(net "DBP_CPU0_HOOK9_MBP3_GTL_QS_R_N")
	)
	(arc
		(start 347.636592 -225.522536)
		(mid 347.505678 -225.386176)
		(end 347.45803 -225.203258)
		(width 0.0889)
		(layer "In4.Cu")
		(net "DBP_CPU0_HOOK9_MBP3_GTL_QS_R_N")
	)
	(arc
		(start 354.215192 -228.778308)
		(mid 354.084278 -228.641948)
		(end 354.03663 -228.45903)
		(width 0.0889)
		(layer "In4.Cu")
		(net "DBP_CPU0_HOOK9_MBP3_GTL_QS_R_N")
	)
	(arc
		(start 352.335846 -227.150422)
		(mid 352.204932 -227.014062)
		(end 352.157284 -226.831144)
		(width 0.0889)
		(layer "In4.Cu")
		(net "DBP_CPU0_HOOK9_MBP3_GTL_QS_R_N")
	)
	(arc
		(start 355.446584 -230.900478)
		(mid 355.372593 -230.620912)
		(end 355.169978 -230.414576)
		(width 0.0889)
		(layer "In4.Cu")
		(net "DBP_CPU0_HOOK9_MBP3_GTL_QS_R_N")
	)
	(arc
		(start 336.368136 -220.644212)
		(mid 336.214069 -220.571473)
		(end 336.050128 -220.525086)
		(width 0.0889)
		(layer "In4.Cu")
		(net "DBP_CPU0_HOOK9_MBP3_GTL_QS_R_N")
	)
	(arc
		(start 347.166946 -224.70872)
		(mid 347.036032 -224.57236)
		(end 346.988384 -224.389442)
		(width 0.0889)
		(layer "In4.Cu")
		(net "DBP_CPU0_HOOK9_MBP3_GTL_QS_R_N")
	)
	(arc
		(start 346.988384 -224.379536)
		(mid 346.910273 -224.102587)
		(end 346.705936 -223.899984)
		(width 0.0889)
		(layer "In4.Cu")
		(net "DBP_CPU0_HOOK9_MBP3_GTL_QS_R_N")
	)
	(arc
		(start 354.03663 -228.436932)
		(mid 353.955719 -228.166804)
		(end 353.754436 -227.969318)
		(width 0.0889)
		(layer "In4.Cu")
		(net "DBP_CPU0_HOOK9_MBP3_GTL_QS_R_N")
	)
	(arc
		(start 348.959678 -225.527616)
		(mid 348.77248 -225.577759)
		(end 348.585282 -225.527616)
		(width 0.0889)
		(layer "In4.Cu")
		(net "DBP_CPU0_HOOK9_MBP3_GTL_QS_R_N")
	)
	(arc
		(start 347.45803 -225.187764)
		(mid 347.37866 -224.91403)
		(end 347.175836 -224.7138)
		(width 0.0889)
		(layer "In4.Cu")
		(net "DBP_CPU0_HOOK9_MBP3_GTL_QS_R_N")
	)
	(arc
		(start 346.227146 -223.080834)
		(mid 346.096232 -222.944474)
		(end 346.048584 -222.761556)
		(width 0.0889)
		(layer "In4.Cu")
		(net "DBP_CPU0_HOOK9_MBP3_GTL_QS_R_N")
	)
	(arc
		(start 344.81135 -222.263462)
		(mid 344.534875 -222.196142)
		(end 344.260678 -222.272098)
		(width 0.0889)
		(layer "In4.Cu")
		(net "DBP_CPU0_HOOK9_MBP3_GTL_QS_R_N")
	)
	(arc
		(start 349.986346 -226.336606)
		(mid 349.855432 -226.200246)
		(end 349.807784 -226.017328)
		(width 0.0889)
		(layer "In4.Cu")
		(net "DBP_CPU0_HOOK9_MBP3_GTL_QS_R_N")
	)
	(arc
		(start 340.11235 -222.263462)
		(mid 339.835875 -222.196142)
		(end 339.561678 -222.272098)
		(width 0.0889)
		(layer "In4.Cu")
		(net "DBP_CPU0_HOOK9_MBP3_GTL_QS_R_N")
	)
	(arc
		(start 342.381078 -222.272098)
		(mid 342.19388 -222.322241)
		(end 342.006682 -222.272098)
		(width 0.0889)
		(layer "In4.Cu")
		(net "DBP_CPU0_HOOK9_MBP3_GTL_QS_R_N")
	)
	(arc
		(start 344.260678 -222.272098)
		(mid 344.07348 -222.322241)
		(end 343.886282 -222.272098)
		(width 0.0889)
		(layer "In4.Cu")
		(net "DBP_CPU0_HOOK9_MBP3_GTL_QS_R_N")
	)
	(arc
		(start 355.6889 -232.168192)
		(mid 355.852932 -231.975243)
		(end 355.91623 -231.730042)
		(width 0.0889)
		(layer "In4.Cu")
		(net "DBP_CPU0_HOOK9_MBP3_GTL_QS_R_N")
	)
	(arc
		(start 340.501478 -222.272098)
		(mid 340.31428 -222.322241)
		(end 340.127082 -222.272098)
		(width 0.0889)
		(layer "In4.Cu")
		(net "DBP_CPU0_HOOK9_MBP3_GTL_QS_R_N")
	)
	(arc
		(start 339.561678 -222.272098)
		(mid 339.37448 -222.322241)
		(end 339.187282 -222.272098)
		(width 0.0889)
		(layer "In4.Cu")
		(net "DBP_CPU0_HOOK9_MBP3_GTL_QS_R_N")
	)
	(arc
		(start 343.320878 -222.272098)
		(mid 343.13368 -222.322241)
		(end 342.946482 -222.272098)
		(width 0.0889)
		(layer "In4.Cu")
		(net "DBP_CPU0_HOOK9_MBP3_GTL_QS_R_N")
	)
	(arc
		(start 355.91623 -231.696006)
		(mid 355.836068 -231.423817)
		(end 355.633782 -231.224836)
		(width 0.0889)
		(layer "In4.Cu")
		(net "DBP_CPU0_HOOK9_MBP3_GTL_QS_R_N")
	)
	(arc
		(start 341.05215 -222.263462)
		(mid 340.775675 -222.196142)
		(end 340.501478 -222.272098)
		(width 0.0889)
		(layer "In4.Cu")
		(net "DBP_CPU0_HOOK9_MBP3_GTL_QS_R_N")
	)
	(arc
		(start 341.99195 -222.263462)
		(mid 341.715475 -222.196142)
		(end 341.441278 -222.272098)
		(width 0.0889)
		(layer "In4.Cu")
		(net "DBP_CPU0_HOOK9_MBP3_GTL_QS_R_N")
	)
	(arc
		(start 354.685346 -229.592124)
		(mid 354.554432 -229.455764)
		(end 354.506784 -229.272846)
		(width 0.0889)
		(layer "In4.Cu")
		(net "DBP_CPU0_HOOK9_MBP3_GTL_QS_R_N")
	)
	(arc
		(start 337.768946 -221.453202)
		(mid 337.638032 -221.316842)
		(end 337.590384 -221.133924)
		(width 0.0889)
		(layer "In4.Cu")
		(net "DBP_CPU0_HOOK9_MBP3_GTL_QS_R_N")
	)
	(arc
		(start 351.874836 -226.341686)
		(mid 351.592134 -226.26591)
		(end 351.309432 -226.341686)
		(width 0.0889)
		(layer "In4.Cu")
		(net "DBP_CPU0_HOOK9_MBP3_GTL_QS_R_N")
	)
	(arc
		(start 352.157284 -226.821238)
		(mid 352.079173 -226.544289)
		(end 351.874836 -226.341686)
		(width 0.0889)
		(layer "In4.Cu")
		(net "DBP_CPU0_HOOK9_MBP3_GTL_QS_R_N")
	)
	(arc
		(start 343.87155 -222.263462)
		(mid 343.595075 -222.196142)
		(end 343.320878 -222.272098)
		(width 0.0889)
		(layer "In4.Cu")
		(net "DBP_CPU0_HOOK9_MBP3_GTL_QS_R_N")
	)
	(segment
		(start 355.35108 -232.250234)
		(end 355.35108 -231.714548)
		(width 0.12954)
		(layer "F.Cu")
		(net "DBP_CPU0_HOOK8_MBP2_GTL_QS_R_N")
	)
	(segment
		(start 355.351334 -232.250488)
		(end 355.35108 -232.250234)
		(width 0.12954)
		(layer "F.Cu")
		(net "DBP_CPU0_HOOK8_MBP2_GTL_QS_R_N")
	)
	(via
		(at 331.395578 -195.575936)
		(size 0.6604)
		(drill 0.3302)
		(layers "F.Cu" "B.Cu")
		(net "DBP_CPU0_HOOK8_MBP2_GTL_QS_R_N")
	)
	(via
		(at 355.35108 -231.714548)
		(size 0.4572)
		(drill 0.2032)
		(layers "F.Cu" "B.Cu")
		(net "DBP_CPU0_HOOK8_MBP2_GTL_QS_R_N")
	)
	(via
		(at 331.28204 -200.21931)
		(size 0.508)
		(drill 0.254)
		(layers "F.Cu" "B.Cu")
		(net "DBP_CPU0_HOOK8_MBP2_GTL_QS_R_N")
	)
	(segment
		(start 331.28204 -200.21931)
		(end 331.441806 -200.059544)
		(width 0.12954)
		(layer "B.Cu")
		(net "DBP_CPU0_HOOK8_MBP2_GTL_QS_R_N")
	)
	(segment
		(start 331.395578 -196.78523)
		(end 331.395578 -195.575936)
		(width 0.12954)
		(layer "B.Cu")
		(net "DBP_CPU0_HOOK8_MBP2_GTL_QS_R_N")
	)
	(segment
		(start 331.540358 -191.913764)
		(end 331.540358 -191.22898)
		(width 0.12954)
		(layer "B.Cu")
		(net "DBP_CPU0_HOOK8_MBP2_GTL_QS_R_N")
	)
	(segment
		(start 331.441806 -196.831458)
		(end 331.395578 -196.78523)
		(width 0.12954)
		(layer "B.Cu")
		(net "DBP_CPU0_HOOK8_MBP2_GTL_QS_R_N")
	)
	(segment
		(start 331.395578 -195.575936)
		(end 331.395578 -192.058544)
		(width 0.12954)
		(layer "B.Cu")
		(net "DBP_CPU0_HOOK8_MBP2_GTL_QS_R_N")
	)
	(segment
		(start 331.441806 -200.059544)
		(end 331.441806 -196.831458)
		(width 0.12954)
		(layer "B.Cu")
		(net "DBP_CPU0_HOOK8_MBP2_GTL_QS_R_N")
	)
	(segment
		(start 331.395578 -192.058544)
		(end 331.540358 -191.913764)
		(width 0.12954)
		(layer "B.Cu")
		(net "DBP_CPU0_HOOK8_MBP2_GTL_QS_R_N")
	)
	(segment
		(start 352.258122 -227.325682)
		(end 352.249232 -227.320602)
		(width 0.0889)
		(layer "In4.Cu")
		(net "DBP_CPU0_HOOK8_MBP2_GTL_QS_R_N")
	)
	(segment
		(start 342.865964 -222.445834)
		(end 342.851232 -222.437198)
		(width 0.0889)
		(layer "In4.Cu")
		(net "DBP_CPU0_HOOK8_MBP2_GTL_QS_R_N")
	)
	(segment
		(start 355.25583 -230.91902)
		(end 355.25583 -230.891842)
		(width 0.0889)
		(layer "In4.Cu")
		(net "DBP_CPU0_HOOK8_MBP2_GTL_QS_R_N")
	)
	(segment
		(start 346.149168 -223.256348)
		(end 346.10167 -223.228916)
		(width 0.0889)
		(layer "In4.Cu")
		(net "DBP_CPU0_HOOK8_MBP2_GTL_QS_R_N")
	)
	(segment
		(start 350.464882 -226.506786)
		(end 350.45015 -226.515422)
		(width 0.0889)
		(layer "In4.Cu")
		(net "DBP_CPU0_HOOK8_MBP2_GTL_QS_R_N")
	)
	(segment
		(start 353.597718 -228.92639)
		(end 353.69119 -228.832664)
		(width 0.0889)
		(layer "In4.Cu")
		(net "DBP_CPU0_HOOK8_MBP2_GTL_QS_R_N")
	)
	(segment
		(start 355.35108 -231.714548)
		(end 355.507544 -231.985566)
		(width 0.0889)
		(layer "In4.Cu")
		(net "DBP_CPU0_HOOK8_MBP2_GTL_QS_R_N")
	)
	(segment
		(start 352.436684 -227.667058)
		(end 352.436684 -227.64496)
		(width 0.0889)
		(layer "In4.Cu")
		(net "DBP_CPU0_HOOK8_MBP2_GTL_QS_R_N")
	)
	(segment
		(start 339.106764 -222.445834)
		(end 339.019896 -222.395034)
		(width 0.0889)
		(layer "In4.Cu")
		(net "DBP_CPU0_HOOK8_MBP2_GTL_QS_R_N")
	)
	(segment
		(start 345.285822 -223.103948)
		(end 345.151202 -222.969328)
		(width 0.0889)
		(layer "In4.Cu")
		(net "DBP_CPU0_HOOK8_MBP2_GTL_QS_R_N")
	)
	(segment
		(start 341.926164 -222.445834)
		(end 341.911432 -222.437198)
		(width 0.0889)
		(layer "In4.Cu")
		(net "DBP_CPU0_HOOK8_MBP2_GTL_QS_R_N")
	)
	(segment
		(start 355.068632 -230.57612)
		(end 355.062536 -230.572564)
		(width 0.0889)
		(layer "In4.Cu")
		(net "DBP_CPU0_HOOK8_MBP2_GTL_QS_R_N")
	)
	(segment
		(start 330.039726 -201.22769)
		(end 330.209906 -201.05751)
		(width 0.127)
		(layer "In4.Cu")
		(net "DBP_CPU0_HOOK8_MBP2_GTL_QS_R_N")
	)
	(segment
		(start 349.438722 -225.69805)
		(end 349.429832 -225.69297)
		(width 0.0889)
		(layer "In4.Cu")
		(net "DBP_CPU0_HOOK8_MBP2_GTL_QS_R_N")
	)
	(segment
		(start 340.046564 -222.445834)
		(end 340.031832 -222.437198)
		(width 0.0889)
		(layer "In4.Cu")
		(net "DBP_CPU0_HOOK8_MBP2_GTL_QS_R_N")
	)
	(segment
		(start 349.617284 -226.032822)
		(end 349.617284 -226.017328)
		(width 0.0889)
		(layer "In4.Cu")
		(net "DBP_CPU0_HOOK8_MBP2_GTL_QS_R_N")
	)
	(segment
		(start 344.938096 -222.55861)
		(end 344.730832 -222.437198)
		(width 0.0889)
		(layer "In4.Cu")
		(net "DBP_CPU0_HOOK8_MBP2_GTL_QS_R_N")
	)
	(segment
		(start 345.758516 -223.137222)
		(end 345.366086 -223.137222)
		(width 0.0889)
		(layer "In4.Cu")
		(net "DBP_CPU0_HOOK8_MBP2_GTL_QS_R_N")
	)
	(segment
		(start 330.509626 -200.21931)
		(end 331.28204 -200.21931)
		(width 0.127)
		(layer "In4.Cu")
		(net "DBP_CPU0_HOOK8_MBP2_GTL_QS_R_N")
	)
	(segment
		(start 347.564964 -225.701606)
		(end 347.550232 -225.69297)
		(width 0.0889)
		(layer "In4.Cu")
		(net "DBP_CPU0_HOOK8_MBP2_GTL_QS_R_N")
	)
	(segment
		(start 330.209906 -201.05751)
		(end 330.209906 -200.51903)
		(width 0.127)
		(layer "In4.Cu")
		(net "DBP_CPU0_HOOK8_MBP2_GTL_QS_R_N")
	)
	(segment
		(start 351.404936 -226.506786)
		(end 351.394522 -226.512882)
		(width 0.0889)
		(layer "In4.Cu")
		(net "DBP_CPU0_HOOK8_MBP2_GTL_QS_R_N")
	)
	(segment
		(start 338.225638 -222.34525)
		(end 338.10194 -222.221806)
		(width 0.0889)
		(layer "In4.Cu")
		(net "DBP_CPU0_HOOK8_MBP2_GTL_QS_R_N")
	)
	(segment
		(start 351.788222 -226.511866)
		(end 351.779332 -226.506786)
		(width 0.0889)
		(layer "In4.Cu")
		(net "DBP_CPU0_HOOK8_MBP2_GTL_QS_R_N")
	)
	(segment
		(start 351.966784 -226.84105)
		(end 351.966784 -226.831144)
		(width 0.0889)
		(layer "In4.Cu")
		(net "DBP_CPU0_HOOK8_MBP2_GTL_QS_R_N")
	)
	(segment
		(start 346.610432 -224.065084)
		(end 346.59824 -224.057972)
		(width 0.0889)
		(layer "In4.Cu")
		(net "DBP_CPU0_HOOK8_MBP2_GTL_QS_R_N")
	)
	(segment
		(start 343.805764 -222.445834)
		(end 343.791032 -222.437198)
		(width 0.0889)
		(layer "In4.Cu")
		(net "DBP_CPU0_HOOK8_MBP2_GTL_QS_R_N")
	)
	(segment
		(start 354.424234 -229.693978)
		(end 353.988116 -229.752144)
		(width 0.0889)
		(layer "In4.Cu")
		(net "DBP_CPU0_HOOK8_MBP2_GTL_QS_R_N")
	)
	(segment
		(start 353.488498 -229.31501)
		(end 353.488498 -229.190042)
		(width 0.0889)
		(layer "In4.Cu")
		(net "DBP_CPU0_HOOK8_MBP2_GTL_QS_R_N")
	)
	(segment
		(start 355.547168 -231.39527)
		(end 355.538278 -231.39019)
		(width 0.0889)
		(layer "In4.Cu")
		(net "DBP_CPU0_HOOK8_MBP2_GTL_QS_R_N")
	)
	(segment
		(start 354.78593 -230.086662)
		(end 354.78593 -230.078026)
		(width 0.0889)
		(layer "In4.Cu")
		(net "DBP_CPU0_HOOK8_MBP2_GTL_QS_R_N")
	)
	(segment
		(start 353.284282 -228.134672)
		(end 353.26955 -228.143308)
		(width 0.0889)
		(layer "In4.Cu")
		(net "DBP_CPU0_HOOK8_MBP2_GTL_QS_R_N")
	)
	(segment
		(start 346.619322 -224.070164)
		(end 346.610432 -224.065084)
		(width 0.0889)
		(layer "In4.Cu")
		(net "DBP_CPU0_HOOK8_MBP2_GTL_QS_R_N")
	)
	(segment
		(start 335.540604 -220.53423)
		(end 334.693006 -219.686632)
		(width 0.0889)
		(layer "In4.Cu")
		(net "DBP_CPU0_HOOK8_MBP2_GTL_QS_R_N")
	)
	(segment
		(start 337.221322 -220.814646)
		(end 337.212432 -220.809566)
		(width 0.0889)
		(layer "In4.Cu")
		(net "DBP_CPU0_HOOK8_MBP2_GTL_QS_R_N")
	)
	(segment
		(start 334.255618 -219.686632)
		(end 333.211424 -219.686632)
		(width 0.127)
		(layer "In4.Cu")
		(net "DBP_CPU0_HOOK8_MBP2_GTL_QS_R_N")
	)
	(segment
		(start 348.504764 -225.701606)
		(end 348.490032 -225.69297)
		(width 0.0889)
		(layer "In4.Cu")
		(net "DBP_CPU0_HOOK8_MBP2_GTL_QS_R_N")
	)
	(segment
		(start 354.598732 -229.762304)
		(end 354.509832 -229.710996)
		(width 0.0889)
		(layer "In4.Cu")
		(net "DBP_CPU0_HOOK8_MBP2_GTL_QS_R_N")
	)
	(segment
		(start 338.974938 -222.382842)
		(end 338.31657 -222.382842)
		(width 0.0889)
		(layer "In4.Cu")
		(net "DBP_CPU0_HOOK8_MBP2_GTL_QS_R_N")
	)
	(segment
		(start 333.211424 -219.686632)
		(end 330.039726 -216.514934)
		(width 0.127)
		(layer "In4.Cu")
		(net "DBP_CPU0_HOOK8_MBP2_GTL_QS_R_N")
	)
	(segment
		(start 330.209906 -200.51903)
		(end 330.509626 -200.21931)
		(width 0.127)
		(layer "In4.Cu")
		(net "DBP_CPU0_HOOK8_MBP2_GTL_QS_R_N")
	)
	(segment
		(start 340.986364 -222.445834)
		(end 340.971632 -222.437198)
		(width 0.0889)
		(layer "In4.Cu")
		(net "DBP_CPU0_HOOK8_MBP2_GTL_QS_R_N")
	)
	(segment
		(start 347.26753 -225.217482)
		(end 347.26753 -225.203258)
		(width 0.0889)
		(layer "In4.Cu")
		(net "DBP_CPU0_HOOK8_MBP2_GTL_QS_R_N")
	)
	(segment
		(start 330.039726 -216.514934)
		(end 330.039726 -201.22769)
		(width 0.127)
		(layer "In4.Cu")
		(net "DBP_CPU0_HOOK8_MBP2_GTL_QS_R_N")
	)
	(segment
		(start 337.829144 -221.708472)
		(end 337.682078 -221.623382)
		(width 0.0889)
		(layer "In4.Cu")
		(net "DBP_CPU0_HOOK8_MBP2_GTL_QS_R_N")
	)
	(segment
		(start 337.399884 -221.149418)
		(end 337.399884 -221.133924)
		(width 0.0889)
		(layer "In4.Cu")
		(net "DBP_CPU0_HOOK8_MBP2_GTL_QS_R_N")
	)
	(segment
		(start 347.088968 -224.88398)
		(end 347.080078 -224.8789)
		(width 0.0889)
		(layer "In4.Cu")
		(net "DBP_CPU0_HOOK8_MBP2_GTL_QS_R_N")
	)
	(segment
		(start 334.693006 -219.686632)
		(end 334.255618 -219.686632)
		(width 0.0889)
		(layer "In4.Cu")
		(net "DBP_CPU0_HOOK8_MBP2_GTL_QS_R_N")
	)
	(segment
		(start 353.667568 -228.139752)
		(end 353.658678 -228.134672)
		(width 0.0889)
		(layer "In4.Cu")
		(net "DBP_CPU0_HOOK8_MBP2_GTL_QS_R_N")
	)
	(segment
		(start 355.507544 -231.985566)
		(end 355.585776 -232.006394)
		(width 0.0889)
		(layer "In4.Cu")
		(net "DBP_CPU0_HOOK8_MBP2_GTL_QS_R_N")
	)
	(segment
		(start 346.797884 -224.404936)
		(end 346.797884 -224.389442)
		(width 0.0889)
		(layer "In4.Cu")
		(net "DBP_CPU0_HOOK8_MBP2_GTL_QS_R_N")
	)
	(arc
		(start 345.151202 -222.969328)
		(mid 345.108692 -222.905568)
		(end 345.093798 -222.83039)
		(width 0.0889)
		(layer "In4.Cu")
		(net "DBP_CPU0_HOOK8_MBP2_GTL_QS_R_N")
	)
	(arc
		(start 355.538278 -231.39019)
		(mid 355.335992 -231.191209)
		(end 355.25583 -230.91902)
		(width 0.0889)
		(layer "In4.Cu")
		(net "DBP_CPU0_HOOK8_MBP2_GTL_QS_R_N")
	)
	(arc
		(start 349.617284 -226.017328)
		(mid 349.569605 -225.834428)
		(end 349.438722 -225.69805)
		(width 0.0889)
		(layer "In4.Cu")
		(net "DBP_CPU0_HOOK8_MBP2_GTL_QS_R_N")
	)
	(arc
		(start 335.916778 -220.71838)
		(mid 335.757893 -220.667327)
		(end 335.609946 -220.59011)
		(width 0.0889)
		(layer "In4.Cu")
		(net "DBP_CPU0_HOOK8_MBP2_GTL_QS_R_N")
	)
	(arc
		(start 345.366086 -223.137222)
		(mid 345.322651 -223.128564)
		(end 345.285822 -223.103948)
		(width 0.0889)
		(layer "In4.Cu")
		(net "DBP_CPU0_HOOK8_MBP2_GTL_QS_R_N")
	)
	(arc
		(start 353.69119 -228.832664)
		(mid 353.805815 -228.661254)
		(end 353.84613 -228.45903)
		(width 0.0889)
		(layer "In4.Cu")
		(net "DBP_CPU0_HOOK8_MBP2_GTL_QS_R_N")
	)
	(arc
		(start 353.84613 -228.45903)
		(mid 353.798451 -228.27613)
		(end 353.667568 -228.139752)
		(width 0.0889)
		(layer "In4.Cu")
		(net "DBP_CPU0_HOOK8_MBP2_GTL_QS_R_N")
	)
	(arc
		(start 347.550232 -225.69297)
		(mid 347.346751 -225.492166)
		(end 347.26753 -225.217482)
		(width 0.0889)
		(layer "In4.Cu")
		(net "DBP_CPU0_HOOK8_MBP2_GTL_QS_R_N")
	)
	(arc
		(start 347.080078 -224.8789)
		(mid 346.877255 -224.678669)
		(end 346.797884 -224.404936)
		(width 0.0889)
		(layer "In4.Cu")
		(net "DBP_CPU0_HOOK8_MBP2_GTL_QS_R_N")
	)
	(arc
		(start 336.272632 -220.809566)
		(mid 336.14346 -220.754181)
		(end 336.004916 -220.730572)
		(width 0.0889)
		(layer "In4.Cu")
		(net "DBP_CPU0_HOOK8_MBP2_GTL_QS_R_N")
	)
	(arc
		(start 349.055436 -225.69297)
		(mid 348.781207 -225.768895)
		(end 348.504764 -225.701606)
		(width 0.0889)
		(layer "In4.Cu")
		(net "DBP_CPU0_HOOK8_MBP2_GTL_QS_R_N")
	)
	(arc
		(start 342.476836 -222.437198)
		(mid 342.202637 -222.513033)
		(end 341.926164 -222.445834)
		(width 0.0889)
		(layer "In4.Cu")
		(net "DBP_CPU0_HOOK8_MBP2_GTL_QS_R_N")
	)
	(arc
		(start 352.436684 -227.64496)
		(mid 352.389005 -227.46206)
		(end 352.258122 -227.325682)
		(width 0.0889)
		(layer "In4.Cu")
		(net "DBP_CPU0_HOOK8_MBP2_GTL_QS_R_N")
	)
	(arc
		(start 338.10194 -222.221806)
		(mid 338.058106 -222.156065)
		(end 338.042758 -222.07855)
		(width 0.0889)
		(layer "In4.Cu")
		(net "DBP_CPU0_HOOK8_MBP2_GTL_QS_R_N")
	)
	(arc
		(start 337.399884 -221.133924)
		(mid 337.352205 -220.951024)
		(end 337.221322 -220.814646)
		(width 0.0889)
		(layer "In4.Cu")
		(net "DBP_CPU0_HOOK8_MBP2_GTL_QS_R_N")
	)
	(arc
		(start 340.031832 -222.437198)
		(mid 339.844634 -222.387055)
		(end 339.657436 -222.437198)
		(width 0.0889)
		(layer "In4.Cu")
		(net "DBP_CPU0_HOOK8_MBP2_GTL_QS_R_N")
	)
	(arc
		(start 352.718878 -228.134672)
		(mid 352.517596 -227.937185)
		(end 352.436684 -227.667058)
		(width 0.0889)
		(layer "In4.Cu")
		(net "DBP_CPU0_HOOK8_MBP2_GTL_QS_R_N")
	)
	(arc
		(start 337.682078 -221.623382)
		(mid 337.479255 -221.423151)
		(end 337.399884 -221.149418)
		(width 0.0889)
		(layer "In4.Cu")
		(net "DBP_CPU0_HOOK8_MBP2_GTL_QS_R_N")
	)
	(arc
		(start 340.971632 -222.437198)
		(mid 340.784434 -222.387055)
		(end 340.597236 -222.437198)
		(width 0.0889)
		(layer "In4.Cu")
		(net "DBP_CPU0_HOOK8_MBP2_GTL_QS_R_N")
	)
	(arc
		(start 354.509832 -229.710996)
		(mid 354.468443 -229.695381)
		(end 354.424234 -229.693978)
		(width 0.0889)
		(layer "In4.Cu")
		(net "DBP_CPU0_HOOK8_MBP2_GTL_QS_R_N")
	)
	(arc
		(start 336.004916 -220.730572)
		(mid 335.960579 -220.726415)
		(end 335.916778 -220.71838)
		(width 0.0889)
		(layer "In4.Cu")
		(net "DBP_CPU0_HOOK8_MBP2_GTL_QS_R_N")
	)
	(arc
		(start 346.10167 -223.228916)
		(mid 345.936119 -223.160504)
		(end 345.758516 -223.137222)
		(width 0.0889)
		(layer "In4.Cu")
		(net "DBP_CPU0_HOOK8_MBP2_GTL_QS_R_N")
	)
	(arc
		(start 344.730832 -222.437198)
		(mid 344.543634 -222.387055)
		(end 344.356436 -222.437198)
		(width 0.0889)
		(layer "In4.Cu")
		(net "DBP_CPU0_HOOK8_MBP2_GTL_QS_R_N")
	)
	(arc
		(start 344.356436 -222.437198)
		(mid 344.082237 -222.513033)
		(end 343.805764 -222.445834)
		(width 0.0889)
		(layer "In4.Cu")
		(net "DBP_CPU0_HOOK8_MBP2_GTL_QS_R_N")
	)
	(arc
		(start 355.72573 -231.714548)
		(mid 355.678051 -231.531648)
		(end 355.547168 -231.39527)
		(width 0.0889)
		(layer "In4.Cu")
		(net "DBP_CPU0_HOOK8_MBP2_GTL_QS_R_N")
	)
	(arc
		(start 351.966784 -226.831144)
		(mid 351.919105 -226.648244)
		(end 351.788222 -226.511866)
		(width 0.0889)
		(layer "In4.Cu")
		(net "DBP_CPU0_HOOK8_MBP2_GTL_QS_R_N")
	)
	(arc
		(start 338.31657 -222.382842)
		(mid 338.267372 -222.373074)
		(end 338.225638 -222.34525)
		(width 0.0889)
		(layer "In4.Cu")
		(net "DBP_CPU0_HOOK8_MBP2_GTL_QS_R_N")
	)
	(arc
		(start 339.657436 -222.437198)
		(mid 339.383237 -222.513033)
		(end 339.106764 -222.445834)
		(width 0.0889)
		(layer "In4.Cu")
		(net "DBP_CPU0_HOOK8_MBP2_GTL_QS_R_N")
	)
	(arc
		(start 340.597236 -222.437198)
		(mid 340.323037 -222.513033)
		(end 340.046564 -222.445834)
		(width 0.0889)
		(layer "In4.Cu")
		(net "DBP_CPU0_HOOK8_MBP2_GTL_QS_R_N")
	)
	(arc
		(start 342.851232 -222.437198)
		(mid 342.664034 -222.387055)
		(end 342.476836 -222.437198)
		(width 0.0889)
		(layer "In4.Cu")
		(net "DBP_CPU0_HOOK8_MBP2_GTL_QS_R_N")
	)
	(arc
		(start 341.911432 -222.437198)
		(mid 341.724234 -222.387055)
		(end 341.537036 -222.437198)
		(width 0.0889)
		(layer "In4.Cu")
		(net "DBP_CPU0_HOOK8_MBP2_GTL_QS_R_N")
	)
	(arc
		(start 349.899478 -226.506786)
		(mid 349.696655 -226.306555)
		(end 349.617284 -226.032822)
		(width 0.0889)
		(layer "In4.Cu")
		(net "DBP_CPU0_HOOK8_MBP2_GTL_QS_R_N")
	)
	(arc
		(start 349.429832 -225.69297)
		(mid 349.242634 -225.642827)
		(end 349.055436 -225.69297)
		(width 0.0889)
		(layer "In4.Cu")
		(net "DBP_CPU0_HOOK8_MBP2_GTL_QS_R_N")
	)
	(arc
		(start 350.45015 -226.515422)
		(mid 350.173675 -226.582742)
		(end 349.899478 -226.506786)
		(width 0.0889)
		(layer "In4.Cu")
		(net "DBP_CPU0_HOOK8_MBP2_GTL_QS_R_N")
	)
	(arc
		(start 338.042758 -222.07855)
		(mid 337.98553 -221.864885)
		(end 337.829144 -221.708472)
		(width 0.0889)
		(layer "In4.Cu")
		(net "DBP_CPU0_HOOK8_MBP2_GTL_QS_R_N")
	)
	(arc
		(start 351.394522 -226.512882)
		(mid 351.11609 -226.582728)
		(end 350.839278 -226.506786)
		(width 0.0889)
		(layer "In4.Cu")
		(net "DBP_CPU0_HOOK8_MBP2_GTL_QS_R_N")
	)
	(arc
		(start 355.062536 -230.572564)
		(mid 354.859949 -230.366213)
		(end 354.78593 -230.086662)
		(width 0.0889)
		(layer "In4.Cu")
		(net "DBP_CPU0_HOOK8_MBP2_GTL_QS_R_N")
	)
	(arc
		(start 350.839278 -226.506786)
		(mid 350.65208 -226.456643)
		(end 350.464882 -226.506786)
		(width 0.0889)
		(layer "In4.Cu")
		(net "DBP_CPU0_HOOK8_MBP2_GTL_QS_R_N")
	)
	(arc
		(start 341.537036 -222.437198)
		(mid 341.262837 -222.513033)
		(end 340.986364 -222.445834)
		(width 0.0889)
		(layer "In4.Cu")
		(net "DBP_CPU0_HOOK8_MBP2_GTL_QS_R_N")
	)
	(arc
		(start 339.019896 -222.395034)
		(mid 338.99823 -222.385935)
		(end 338.974938 -222.382842)
		(width 0.0889)
		(layer "In4.Cu")
		(net "DBP_CPU0_HOOK8_MBP2_GTL_QS_R_N")
	)
	(arc
		(start 347.26753 -225.203258)
		(mid 347.219851 -225.020358)
		(end 347.088968 -224.88398)
		(width 0.0889)
		(layer "In4.Cu")
		(net "DBP_CPU0_HOOK8_MBP2_GTL_QS_R_N")
	)
	(arc
		(start 352.249232 -227.320602)
		(mid 352.044897 -227.117997)
		(end 351.966784 -226.84105)
		(width 0.0889)
		(layer "In4.Cu")
		(net "DBP_CPU0_HOOK8_MBP2_GTL_QS_R_N")
	)
	(arc
		(start 348.115636 -225.69297)
		(mid 347.841407 -225.768895)
		(end 347.564964 -225.701606)
		(width 0.0889)
		(layer "In4.Cu")
		(net "DBP_CPU0_HOOK8_MBP2_GTL_QS_R_N")
	)
	(arc
		(start 346.32773 -223.575626)
		(mid 346.280051 -223.392726)
		(end 346.149168 -223.256348)
		(width 0.0889)
		(layer "In4.Cu")
		(net "DBP_CPU0_HOOK8_MBP2_GTL_QS_R_N")
	)
	(arc
		(start 343.791032 -222.437198)
		(mid 343.603834 -222.387055)
		(end 343.416636 -222.437198)
		(width 0.0889)
		(layer "In4.Cu")
		(net "DBP_CPU0_HOOK8_MBP2_GTL_QS_R_N")
	)
	(arc
		(start 354.78593 -230.078026)
		(mid 354.73366 -229.895661)
		(end 354.598732 -229.762304)
		(width 0.0889)
		(layer "In4.Cu")
		(net "DBP_CPU0_HOOK8_MBP2_GTL_QS_R_N")
	)
	(arc
		(start 343.416636 -222.437198)
		(mid 343.142437 -222.513033)
		(end 342.865964 -222.445834)
		(width 0.0889)
		(layer "In4.Cu")
		(net "DBP_CPU0_HOOK8_MBP2_GTL_QS_R_N")
	)
	(arc
		(start 335.609946 -220.59011)
		(mid 335.573749 -220.564064)
		(end 335.540604 -220.53423)
		(width 0.0889)
		(layer "In4.Cu")
		(net "DBP_CPU0_HOOK8_MBP2_GTL_QS_R_N")
	)
	(arc
		(start 355.585776 -232.006394)
		(mid 355.688921 -231.876369)
		(end 355.72573 -231.714548)
		(width 0.0889)
		(layer "In4.Cu")
		(net "DBP_CPU0_HOOK8_MBP2_GTL_QS_R_N")
	)
	(arc
		(start 346.797884 -224.389442)
		(mid 346.750205 -224.206542)
		(end 346.619322 -224.070164)
		(width 0.0889)
		(layer "In4.Cu")
		(net "DBP_CPU0_HOOK8_MBP2_GTL_QS_R_N")
	)
	(arc
		(start 345.093798 -222.83039)
		(mid 345.052108 -222.67379)
		(end 344.938096 -222.55861)
		(width 0.0889)
		(layer "In4.Cu")
		(net "DBP_CPU0_HOOK8_MBP2_GTL_QS_R_N")
	)
	(arc
		(start 353.658678 -228.134672)
		(mid 353.47148 -228.084529)
		(end 353.284282 -228.134672)
		(width 0.0889)
		(layer "In4.Cu")
		(net "DBP_CPU0_HOOK8_MBP2_GTL_QS_R_N")
	)
	(arc
		(start 351.779332 -226.506786)
		(mid 351.592134 -226.456643)
		(end 351.404936 -226.506786)
		(width 0.0889)
		(layer "In4.Cu")
		(net "DBP_CPU0_HOOK8_MBP2_GTL_QS_R_N")
	)
	(arc
		(start 346.59824 -224.057972)
		(mid 346.400012 -223.852124)
		(end 346.32773 -223.575626)
		(width 0.0889)
		(layer "In4.Cu")
		(net "DBP_CPU0_HOOK8_MBP2_GTL_QS_R_N")
	)
	(arc
		(start 353.988116 -229.752144)
		(mid 353.639137 -229.646971)
		(end 353.488498 -229.31501)
		(width 0.0889)
		(layer "In4.Cu")
		(net "DBP_CPU0_HOOK8_MBP2_GTL_QS_R_N")
	)
	(arc
		(start 353.488498 -229.190042)
		(mid 353.516881 -229.04735)
		(end 353.597718 -228.92639)
		(width 0.0889)
		(layer "In4.Cu")
		(net "DBP_CPU0_HOOK8_MBP2_GTL_QS_R_N")
	)
	(arc
		(start 336.838036 -220.809566)
		(mid 336.555334 -220.885308)
		(end 336.272632 -220.809566)
		(width 0.0889)
		(layer "In4.Cu")
		(net "DBP_CPU0_HOOK8_MBP2_GTL_QS_R_N")
	)
	(arc
		(start 348.490032 -225.69297)
		(mid 348.302834 -225.642827)
		(end 348.115636 -225.69297)
		(width 0.0889)
		(layer "In4.Cu")
		(net "DBP_CPU0_HOOK8_MBP2_GTL_QS_R_N")
	)
	(arc
		(start 337.212432 -220.809566)
		(mid 337.025234 -220.759423)
		(end 336.838036 -220.809566)
		(width 0.0889)
		(layer "In4.Cu")
		(net "DBP_CPU0_HOOK8_MBP2_GTL_QS_R_N")
	)
	(arc
		(start 355.25583 -230.891842)
		(mid 355.20356 -230.709477)
		(end 355.068632 -230.57612)
		(width 0.0889)
		(layer "In4.Cu")
		(net "DBP_CPU0_HOOK8_MBP2_GTL_QS_R_N")
	)
	(arc
		(start 353.26955 -228.143308)
		(mid 352.993109 -228.210474)
		(end 352.718878 -228.134672)
		(width 0.0889)
		(layer "In4.Cu")
		(net "DBP_CPU0_HOOK8_MBP2_GTL_QS_R_N")
	)
	(segment
		(start 201.73188 -108.022898)
		(end 202.09383 -107.660948)
		(width 0.12954)
		(layer "F.Cu")
		(net "CPU_RMCA_CATERR_LVT3_N")
	)
	(segment
		(start 203.00188 -107.660948)
		(end 204.194918 -107.660948)
		(width 0.12954)
		(layer "F.Cu")
		(net "CPU_RMCA_CATERR_LVT3_N")
	)
	(segment
		(start 202.09383 -107.660948)
		(end 203.00188 -107.660948)
		(width 0.12954)
		(layer "F.Cu")
		(net "CPU_RMCA_CATERR_LVT3_N")
	)
	(segment
		(start 204.194918 -107.660948)
		(end 204.59192 -108.05795)
		(width 0.12954)
		(layer "F.Cu")
		(net "CPU_RMCA_CATERR_LVT3_N")
	)
	(via
		(at 203.00188 -107.660948)
		(size 0.762)
		(drill 0.381)
		(layers "F.Cu" "B.Cu")
		(net "CPU_RMCA_CATERR_LVT3_N")
	)
	(segment
		(start 116.919248 -265.592306)
		(end 116.918994 -265.59256)
		(width 0.12954)
		(layer "F.Cu")
		(net "CPU1_RSVD<98>")
	)
	(segment
		(start 116.918994 -265.59256)
		(end 116.918994 -266.1285)
		(width 0.12954)
		(layer "F.Cu")
		(net "CPU1_RSVD<98>")
	)
	(via
		(at 116.918994 -266.1285)
		(size 0.4572)
		(drill 0.2032)
		(layers "F.Cu" "B.Cu")
		(net "CPU1_RSVD<98>")
	)
	(segment
		(start 115.039394 -272.103596)
		(end 115.039394 -272.639282)
		(width 0.12954)
		(layer "F.Cu")
		(net "CPU1_RSVD<85>")
	)
	(segment
		(start 115.039648 -272.103342)
		(end 115.039394 -272.103596)
		(width 0.12954)
		(layer "F.Cu")
		(net "CPU1_RSVD<85>")
	)
	(via
		(at 115.039394 -272.639282)
		(size 0.4572)
		(drill 0.2032)
		(layers "F.Cu" "B.Cu")
		(net "CPU1_RSVD<85>")
	)
	(segment
		(start 114.569494 -272.917158)
		(end 114.569494 -273.453098)
		(width 0.12954)
		(layer "F.Cu")
		(net "CPU1_RSVD<82>")
	)
	(via
		(at 114.569494 -273.453098)
		(size 0.4572)
		(drill 0.2032)
		(layers "F.Cu" "B.Cu")
		(net "CPU1_RSVD<82>")
	)
	(segment
		(start 109.870494 -271.289272)
		(end 109.87024 -271.289526)
		(width 0.12954)
		(layer "F.Cu")
		(net "CPU1_RSVD<65>")
	)
	(segment
		(start 109.87024 -271.289526)
		(end 109.87024 -271.825212)
		(width 0.12954)
		(layer "F.Cu")
		(net "CPU1_RSVD<65>")
	)
	(via
		(at 109.87024 -271.825212)
		(size 0.4572)
		(drill 0.2032)
		(layers "F.Cu" "B.Cu")
		(net "CPU1_RSVD<65>")
	)
	(segment
		(start 107.521248 -272.103342)
		(end 107.520994 -272.103596)
		(width 0.12954)
		(layer "F.Cu")
		(net "CPU1_RSVD<54>")
	)
	(segment
		(start 107.520994 -272.103596)
		(end 107.520994 -272.639282)
		(width 0.12954)
		(layer "F.Cu")
		(net "CPU1_RSVD<54>")
	)
	(via
		(at 84.250022 -276.317456)
		(size 0.6604)
		(drill 0.3302)
		(layers "F.Cu" "B.Cu")
		(net "CPU1_RSVD<54>")
	)
	(via
		(at 107.520994 -272.639282)
		(size 0.4572)
		(drill 0.2032)
		(layers "F.Cu" "B.Cu")
		(net "CPU1_RSVD<54>")
	)
	(segment
		(start 107.333796 -272.96364)
		(end 107.324906 -272.95856)
		(width 0.0889)
		(layer "B.Cu")
		(net "CPU1_RSVD<54>")
	)
	(segment
		(start 104.797098 -275.094954)
		(end 104.797098 -275.08073)
		(width 0.0889)
		(layer "B.Cu")
		(net "CPU1_RSVD<54>")
	)
	(segment
		(start 91.342464 -275.579078)
		(end 91.357196 -275.570442)
		(width 0.0889)
		(layer "B.Cu")
		(net "CPU1_RSVD<54>")
	)
	(segment
		(start 105.358946 -274.756372)
		(end 105.36936 -274.762468)
		(width 0.0889)
		(layer "B.Cu")
		(net "CPU1_RSVD<54>")
	)
	(segment
		(start 103.559864 -275.579078)
		(end 103.574596 -275.570442)
		(width 0.0889)
		(layer "B.Cu")
		(net "CPU1_RSVD<54>")
	)
	(segment
		(start 95.105982 -275.576538)
		(end 95.116396 -275.570442)
		(width 0.0889)
		(layer "B.Cu")
		(net "CPU1_RSVD<54>")
	)
	(segment
		(start 107.146344 -274.282408)
		(end 107.146344 -274.266914)
		(width 0.0889)
		(layer "B.Cu")
		(net "CPU1_RSVD<54>")
	)
	(segment
		(start 96.981264 -275.579078)
		(end 96.995996 -275.570442)
		(width 0.0889)
		(layer "B.Cu")
		(net "CPU1_RSVD<54>")
	)
	(segment
		(start 104.499664 -275.579078)
		(end 104.514396 -275.570442)
		(width 0.0889)
		(layer "B.Cu")
		(net "CPU1_RSVD<54>")
	)
	(segment
		(start 84.912708 -275.958554)
		(end 85.224874 -275.646388)
		(width 0.0889)
		(layer "B.Cu")
		(net "CPU1_RSVD<54>")
	)
	(segment
		(start 101.684582 -275.576538)
		(end 101.694996 -275.570442)
		(width 0.0889)
		(layer "B.Cu")
		(net "CPU1_RSVD<54>")
	)
	(segment
		(start 107.36453 -272.368264)
		(end 107.520994 -272.639282)
		(width 0.0889)
		(layer "B.Cu")
		(net "CPU1_RSVD<54>")
	)
	(segment
		(start 100.745036 -275.576538)
		(end 100.75545 -275.570442)
		(width 0.0889)
		(layer "B.Cu")
		(net "CPU1_RSVD<54>")
	)
	(segment
		(start 102.620064 -275.579078)
		(end 102.634796 -275.570442)
		(width 0.0889)
		(layer "B.Cu")
		(net "CPU1_RSVD<54>")
	)
	(segment
		(start 93.222064 -275.579078)
		(end 93.236796 -275.570442)
		(width 0.0889)
		(layer "B.Cu")
		(net "CPU1_RSVD<54>")
	)
	(segment
		(start 97.921064 -275.579078)
		(end 97.935796 -275.570442)
		(width 0.0889)
		(layer "B.Cu")
		(net "CPU1_RSVD<54>")
	)
	(segment
		(start 107.324906 -273.947636)
		(end 107.333796 -273.942556)
		(width 0.0889)
		(layer "B.Cu")
		(net "CPU1_RSVD<54>")
	)
	(segment
		(start 96.041464 -275.579078)
		(end 96.056196 -275.570442)
		(width 0.0889)
		(layer "B.Cu")
		(net "CPU1_RSVD<54>")
	)
	(segment
		(start 99.800664 -275.579078)
		(end 99.815396 -275.570442)
		(width 0.0889)
		(layer "B.Cu")
		(net "CPU1_RSVD<54>")
	)
	(segment
		(start 84.553806 -276.317456)
		(end 84.912708 -275.958554)
		(width 0.12954)
		(layer "B.Cu")
		(net "CPU1_RSVD<54>")
	)
	(segment
		(start 107.339892 -272.967196)
		(end 107.333796 -272.96364)
		(width 0.0889)
		(layer "B.Cu")
		(net "CPU1_RSVD<54>")
	)
	(segment
		(start 104.97566 -274.761452)
		(end 104.98455 -274.756372)
		(width 0.0889)
		(layer "B.Cu")
		(net "CPU1_RSVD<54>")
	)
	(segment
		(start 88.527382 -275.576538)
		(end 88.537796 -275.570442)
		(width 0.0889)
		(layer "B.Cu")
		(net "CPU1_RSVD<54>")
	)
	(segment
		(start 85.224874 -275.646388)
		(end 86.37524 -275.646388)
		(width 0.0889)
		(layer "B.Cu")
		(net "CPU1_RSVD<54>")
	)
	(segment
		(start 87.032592 -275.570442)
		(end 87.043006 -275.576538)
		(width 0.0889)
		(layer "B.Cu")
		(net "CPU1_RSVD<54>")
	)
	(segment
		(start 84.250022 -276.317456)
		(end 84.553806 -276.317456)
		(width 0.12954)
		(layer "B.Cu")
		(net "CPU1_RSVD<54>")
	)
	(segment
		(start 107.286298 -272.347436)
		(end 107.36453 -272.368264)
		(width 0.0889)
		(layer "B.Cu")
		(net "CPU1_RSVD<54>")
	)
	(segment
		(start 94.166436 -275.576538)
		(end 94.17685 -275.570442)
		(width 0.0889)
		(layer "B.Cu")
		(net "CPU1_RSVD<54>")
	)
	(segment
		(start 107.333796 -273.942556)
		(end 107.339892 -273.939)
		(width 0.0889)
		(layer "B.Cu")
		(net "CPU1_RSVD<54>")
	)
	(segment
		(start 106.298492 -274.756372)
		(end 106.308906 -274.762468)
		(width 0.0889)
		(layer "B.Cu")
		(net "CPU1_RSVD<54>")
	)
	(arc
		(start 88.912192 -275.570442)
		(mid 89.194894 -275.646184)
		(end 89.477596 -275.570442)
		(width 0.0889)
		(layer "B.Cu")
		(net "CPU1_RSVD<54>")
	)
	(arc
		(start 89.851992 -275.570442)
		(mid 90.134694 -275.646184)
		(end 90.417396 -275.570442)
		(width 0.0889)
		(layer "B.Cu")
		(net "CPU1_RSVD<54>")
	)
	(arc
		(start 105.924096 -274.756372)
		(mid 106.111294 -274.706229)
		(end 106.298492 -274.756372)
		(width 0.0889)
		(layer "B.Cu")
		(net "CPU1_RSVD<54>")
	)
	(arc
		(start 97.370392 -275.570442)
		(mid 97.644621 -275.646367)
		(end 97.921064 -275.579078)
		(width 0.0889)
		(layer "B.Cu")
		(net "CPU1_RSVD<54>")
	)
	(arc
		(start 103.009192 -275.570442)
		(mid 103.283421 -275.646367)
		(end 103.559864 -275.579078)
		(width 0.0889)
		(layer "B.Cu")
		(net "CPU1_RSVD<54>")
	)
	(arc
		(start 98.875596 -275.570442)
		(mid 99.062794 -275.520299)
		(end 99.249992 -275.570442)
		(width 0.0889)
		(layer "B.Cu")
		(net "CPU1_RSVD<54>")
	)
	(arc
		(start 91.731592 -275.570442)
		(mid 92.014294 -275.646184)
		(end 92.296996 -275.570442)
		(width 0.0889)
		(layer "B.Cu")
		(net "CPU1_RSVD<54>")
	)
	(arc
		(start 94.551246 -275.570442)
		(mid 94.827805 -275.646151)
		(end 95.105982 -275.576538)
		(width 0.0889)
		(layer "B.Cu")
		(net "CPU1_RSVD<54>")
	)
	(arc
		(start 103.574596 -275.570442)
		(mid 103.761794 -275.520299)
		(end 103.948992 -275.570442)
		(width 0.0889)
		(layer "B.Cu")
		(net "CPU1_RSVD<54>")
	)
	(arc
		(start 91.357196 -275.570442)
		(mid 91.544394 -275.520299)
		(end 91.731592 -275.570442)
		(width 0.0889)
		(layer "B.Cu")
		(net "CPU1_RSVD<54>")
	)
	(arc
		(start 92.296996 -275.570442)
		(mid 92.484194 -275.520299)
		(end 92.671392 -275.570442)
		(width 0.0889)
		(layer "B.Cu")
		(net "CPU1_RSVD<54>")
	)
	(arc
		(start 107.146344 -272.639282)
		(mid 107.183204 -272.477485)
		(end 107.286298 -272.347436)
		(width 0.0889)
		(layer "B.Cu")
		(net "CPU1_RSVD<54>")
	)
	(arc
		(start 96.995996 -275.570442)
		(mid 97.183194 -275.520299)
		(end 97.370392 -275.570442)
		(width 0.0889)
		(layer "B.Cu")
		(net "CPU1_RSVD<54>")
	)
	(arc
		(start 99.249992 -275.570442)
		(mid 99.524221 -275.646367)
		(end 99.800664 -275.579078)
		(width 0.0889)
		(layer "B.Cu")
		(net "CPU1_RSVD<54>")
	)
	(arc
		(start 104.98455 -274.756372)
		(mid 105.171748 -274.706229)
		(end 105.358946 -274.756372)
		(width 0.0889)
		(layer "B.Cu")
		(net "CPU1_RSVD<54>")
	)
	(arc
		(start 100.75545 -275.570442)
		(mid 100.942648 -275.520299)
		(end 101.129846 -275.570442)
		(width 0.0889)
		(layer "B.Cu")
		(net "CPU1_RSVD<54>")
	)
	(arc
		(start 90.791792 -275.570442)
		(mid 91.066021 -275.646367)
		(end 91.342464 -275.579078)
		(width 0.0889)
		(layer "B.Cu")
		(net "CPU1_RSVD<54>")
	)
	(arc
		(start 104.514396 -275.570442)
		(mid 104.717877 -275.369638)
		(end 104.797098 -275.094954)
		(width 0.0889)
		(layer "B.Cu")
		(net "CPU1_RSVD<54>")
	)
	(arc
		(start 102.634796 -275.570442)
		(mid 102.821994 -275.520299)
		(end 103.009192 -275.570442)
		(width 0.0889)
		(layer "B.Cu")
		(net "CPU1_RSVD<54>")
	)
	(arc
		(start 89.477596 -275.570442)
		(mid 89.664794 -275.520299)
		(end 89.851992 -275.570442)
		(width 0.0889)
		(layer "B.Cu")
		(net "CPU1_RSVD<54>")
	)
	(arc
		(start 94.17685 -275.570442)
		(mid 94.364048 -275.520299)
		(end 94.551246 -275.570442)
		(width 0.0889)
		(layer "B.Cu")
		(net "CPU1_RSVD<54>")
	)
	(arc
		(start 107.324906 -272.95856)
		(mid 107.193992 -272.8222)
		(end 107.146344 -272.639282)
		(width 0.0889)
		(layer "B.Cu")
		(net "CPU1_RSVD<54>")
	)
	(arc
		(start 98.310192 -275.570442)
		(mid 98.592894 -275.646184)
		(end 98.875596 -275.570442)
		(width 0.0889)
		(layer "B.Cu")
		(net "CPU1_RSVD<54>")
	)
	(arc
		(start 87.972138 -275.570442)
		(mid 88.248951 -275.646278)
		(end 88.527382 -275.576538)
		(width 0.0889)
		(layer "B.Cu")
		(net "CPU1_RSVD<54>")
	)
	(arc
		(start 95.490792 -275.570442)
		(mid 95.765021 -275.646367)
		(end 96.041464 -275.579078)
		(width 0.0889)
		(layer "B.Cu")
		(net "CPU1_RSVD<54>")
	)
	(arc
		(start 88.537796 -275.570442)
		(mid 88.724994 -275.520299)
		(end 88.912192 -275.570442)
		(width 0.0889)
		(layer "B.Cu")
		(net "CPU1_RSVD<54>")
	)
	(arc
		(start 92.671392 -275.570442)
		(mid 92.945621 -275.646367)
		(end 93.222064 -275.579078)
		(width 0.0889)
		(layer "B.Cu")
		(net "CPU1_RSVD<54>")
	)
	(arc
		(start 90.417396 -275.570442)
		(mid 90.604594 -275.520299)
		(end 90.791792 -275.570442)
		(width 0.0889)
		(layer "B.Cu")
		(net "CPU1_RSVD<54>")
	)
	(arc
		(start 102.069392 -275.570442)
		(mid 102.343621 -275.646367)
		(end 102.620064 -275.579078)
		(width 0.0889)
		(layer "B.Cu")
		(net "CPU1_RSVD<54>")
	)
	(arc
		(start 107.146344 -274.266914)
		(mid 107.194023 -274.084014)
		(end 107.324906 -273.947636)
		(width 0.0889)
		(layer "B.Cu")
		(net "CPU1_RSVD<54>")
	)
	(arc
		(start 86.658196 -275.570442)
		(mid 86.845394 -275.520299)
		(end 87.032592 -275.570442)
		(width 0.0889)
		(layer "B.Cu")
		(net "CPU1_RSVD<54>")
	)
	(arc
		(start 87.043006 -275.576538)
		(mid 87.321184 -275.64623)
		(end 87.597742 -275.570442)
		(width 0.0889)
		(layer "B.Cu")
		(net "CPU1_RSVD<54>")
	)
	(arc
		(start 96.056196 -275.570442)
		(mid 96.243394 -275.520299)
		(end 96.430592 -275.570442)
		(width 0.0889)
		(layer "B.Cu")
		(net "CPU1_RSVD<54>")
	)
	(arc
		(start 93.236796 -275.570442)
		(mid 93.423994 -275.520299)
		(end 93.611192 -275.570442)
		(width 0.0889)
		(layer "B.Cu")
		(net "CPU1_RSVD<54>")
	)
	(arc
		(start 103.948992 -275.570442)
		(mid 104.223221 -275.646367)
		(end 104.499664 -275.579078)
		(width 0.0889)
		(layer "B.Cu")
		(net "CPU1_RSVD<54>")
	)
	(arc
		(start 93.611192 -275.570442)
		(mid 93.888005 -275.646278)
		(end 94.166436 -275.576538)
		(width 0.0889)
		(layer "B.Cu")
		(net "CPU1_RSVD<54>")
	)
	(arc
		(start 97.935796 -275.570442)
		(mid 98.122994 -275.520299)
		(end 98.310192 -275.570442)
		(width 0.0889)
		(layer "B.Cu")
		(net "CPU1_RSVD<54>")
	)
	(arc
		(start 95.116396 -275.570442)
		(mid 95.303594 -275.520299)
		(end 95.490792 -275.570442)
		(width 0.0889)
		(layer "B.Cu")
		(net "CPU1_RSVD<54>")
	)
	(arc
		(start 106.308906 -274.762468)
		(mid 106.587338 -274.832314)
		(end 106.86415 -274.756372)
		(width 0.0889)
		(layer "B.Cu")
		(net "CPU1_RSVD<54>")
	)
	(arc
		(start 101.694996 -275.570442)
		(mid 101.882194 -275.520299)
		(end 102.069392 -275.570442)
		(width 0.0889)
		(layer "B.Cu")
		(net "CPU1_RSVD<54>")
	)
	(arc
		(start 104.797098 -275.08073)
		(mid 104.844777 -274.89783)
		(end 104.97566 -274.761452)
		(width 0.0889)
		(layer "B.Cu")
		(net "CPU1_RSVD<54>")
	)
	(arc
		(start 106.86415 -274.756372)
		(mid 107.066973 -274.556141)
		(end 107.146344 -274.282408)
		(width 0.0889)
		(layer "B.Cu")
		(net "CPU1_RSVD<54>")
	)
	(arc
		(start 105.36936 -274.762468)
		(mid 105.647538 -274.832191)
		(end 105.924096 -274.756372)
		(width 0.0889)
		(layer "B.Cu")
		(net "CPU1_RSVD<54>")
	)
	(arc
		(start 99.815396 -275.570442)
		(mid 100.002594 -275.520299)
		(end 100.189792 -275.570442)
		(width 0.0889)
		(layer "B.Cu")
		(net "CPU1_RSVD<54>")
	)
	(arc
		(start 107.339892 -273.939)
		(mid 107.616466 -273.453098)
		(end 107.339892 -272.967196)
		(width 0.0889)
		(layer "B.Cu")
		(net "CPU1_RSVD<54>")
	)
	(arc
		(start 86.37524 -275.646388)
		(mid 86.52171 -275.627028)
		(end 86.658196 -275.570442)
		(width 0.0889)
		(layer "B.Cu")
		(net "CPU1_RSVD<54>")
	)
	(arc
		(start 87.597742 -275.570442)
		(mid 87.78494 -275.520299)
		(end 87.972138 -275.570442)
		(width 0.0889)
		(layer "B.Cu")
		(net "CPU1_RSVD<54>")
	)
	(arc
		(start 100.189792 -275.570442)
		(mid 100.466605 -275.646278)
		(end 100.745036 -275.576538)
		(width 0.0889)
		(layer "B.Cu")
		(net "CPU1_RSVD<54>")
	)
	(arc
		(start 96.430592 -275.570442)
		(mid 96.704821 -275.646367)
		(end 96.981264 -275.579078)
		(width 0.0889)
		(layer "B.Cu")
		(net "CPU1_RSVD<54>")
	)
	(arc
		(start 101.129846 -275.570442)
		(mid 101.406405 -275.646151)
		(end 101.684582 -275.576538)
		(width 0.0889)
		(layer "B.Cu")
		(net "CPU1_RSVD<54>")
	)
	(segment
		(start 103.292148 -268.034008)
		(end 103.292148 -268.569694)
		(width 0.12954)
		(layer "F.Cu")
		(net "CPU1_RSVD<27>")
	)
	(segment
		(start 103.291894 -268.033754)
		(end 103.292148 -268.034008)
		(width 0.12954)
		(layer "F.Cu")
		(net "CPU1_RSVD<27>")
	)
	(via
		(at 103.292148 -268.569694)
		(size 0.4572)
		(drill 0.2032)
		(layers "F.Cu" "B.Cu")
		(net "CPU1_RSVD<27>")
	)
	(segment
		(start 103.182166 -234.691936)
		(end 103.182166 -234.15625)
		(width 0.12954)
		(layer "F.Cu")
		(net "CPU1_RSVD<25>")
	)
	(segment
		(start 103.181912 -234.69219)
		(end 103.182166 -234.691936)
		(width 0.12954)
		(layer "F.Cu")
		(net "CPU1_RSVD<25>")
	)
	(via
		(at 103.182166 -234.15625)
		(size 0.4572)
		(drill 0.2032)
		(layers "F.Cu" "B.Cu")
		(net "CPU1_RSVD<25>")
	)
	(segment
		(start 102.242112 -234.156504)
		(end 102.242366 -234.15625)
		(width 0.12954)
		(layer "F.Cu")
		(net "CPU1_RSVD<15>")
	)
	(segment
		(start 102.242112 -234.69219)
		(end 102.242112 -234.156504)
		(width 0.12954)
		(layer "F.Cu")
		(net "CPU1_RSVD<15>")
	)
	(via
		(at 102.242366 -234.15625)
		(size 0.4572)
		(drill 0.2032)
		(layers "F.Cu" "B.Cu")
		(net "CPU1_RSVD<15>")
	)
	(segment
		(start 87.675466 -217.06459)
		(end 87.675212 -217.064336)
		(width 0.12954)
		(layer "F.Cu")
		(net "CPU1_RSVD<157>")
	)
	(segment
		(start 87.675466 -217.600276)
		(end 87.675466 -217.06459)
		(width 0.12954)
		(layer "F.Cu")
		(net "CPU1_RSVD<157>")
	)
	(via
		(at 87.675212 -217.064336)
		(size 0.4572)
		(drill 0.2032)
		(layers "F.Cu" "B.Cu")
		(net "CPU1_RSVD<157>")
	)
	(segment
		(start 86.265766 -216.78646)
		(end 85.862668 -216.383362)
		(width 0.12954)
		(layer "F.Cu")
		(net "CPU1_RSVD<153>")
	)
	(segment
		(start 85.862668 -216.383362)
		(end 85.862668 -215.894412)
		(width 0.12954)
		(layer "F.Cu")
		(net "CPU1_RSVD<153>")
	)
	(via
		(at 85.862668 -215.894412)
		(size 0.4572)
		(drill 0.2032)
		(layers "F.Cu" "B.Cu")
		(net "CPU1_RSVD<153>")
	)
	(segment
		(start 121.618248 -271.011142)
		(end 121.617994 -271.011396)
		(width 0.12954)
		(layer "F.Cu")
		(net "CPU1_RSVD<144>")
	)
	(segment
		(start 121.618248 -270.475456)
		(end 121.618248 -271.011142)
		(width 0.12954)
		(layer "F.Cu")
		(net "CPU1_RSVD<144>")
	)
	(via
		(at 121.617994 -271.011396)
		(size 0.4572)
		(drill 0.2032)
		(layers "F.Cu" "B.Cu")
		(net "CPU1_RSVD<144>")
	)
	(segment
		(start 121.508266 -233.34218)
		(end 121.508266 -233.87812)
		(width 0.12954)
		(layer "F.Cu")
		(net "CPU1_RSVD<140>")
	)
	(via
		(at 121.508266 -233.34218)
		(size 0.4572)
		(drill 0.2032)
		(layers "F.Cu" "B.Cu")
		(net "CPU1_RSVD<140>")
	)
	(segment
		(start 121.508266 -231.714802)
		(end 121.50852 -231.714548)
		(width 0.12954)
		(layer "F.Cu")
		(net "CPU1_RSVD<139>")
	)
	(segment
		(start 121.508266 -232.250488)
		(end 121.508266 -231.714802)
		(width 0.12954)
		(layer "F.Cu")
		(net "CPU1_RSVD<139>")
	)
	(via
		(at 121.50852 -231.714548)
		(size 0.4572)
		(drill 0.2032)
		(layers "F.Cu" "B.Cu")
		(net "CPU1_RSVD<139>")
	)
	(segment
		(start 121.038112 -233.064304)
		(end 121.038112 -232.528618)
		(width 0.12954)
		(layer "F.Cu")
		(net "CPU1_RSVD<135>")
	)
	(segment
		(start 121.038112 -232.528618)
		(end 121.038366 -232.528364)
		(width 0.12954)
		(layer "F.Cu")
		(net "CPU1_RSVD<135>")
	)
	(via
		(at 121.038366 -232.528364)
		(size 0.4572)
		(drill 0.2032)
		(layers "F.Cu" "B.Cu")
		(net "CPU1_RSVD<135>")
	)
	(segment
		(start 119.628666 -231.714802)
		(end 119.62892 -231.714548)
		(width 0.12954)
		(layer "F.Cu")
		(net "CPU1_RSVD<126>")
	)
	(segment
		(start 119.628666 -232.250488)
		(end 119.628666 -231.714802)
		(width 0.12954)
		(layer "F.Cu")
		(net "CPU1_RSVD<126>")
	)
	(via
		(at 119.62892 -231.714548)
		(size 0.4572)
		(drill 0.2032)
		(layers "F.Cu" "B.Cu")
		(net "CPU1_RSVD<126>")
	)
	(segment
		(start 118.798594 -265.59256)
		(end 118.798594 -266.1285)
		(width 0.12954)
		(layer "F.Cu")
		(net "CPU1_RSVD<120>")
	)
	(segment
		(start 118.798848 -265.592306)
		(end 118.798594 -265.59256)
		(width 0.12954)
		(layer "F.Cu")
		(net "CPU1_RSVD<120>")
	)
	(via
		(at 118.798594 -266.1285)
		(size 0.4572)
		(drill 0.2032)
		(layers "F.Cu" "B.Cu")
		(net "CPU1_RSVD<120>")
	)
	(segment
		(start 118.328694 -266.405868)
		(end 118.32844 -266.406122)
		(width 0.12954)
		(layer "F.Cu")
		(net "CPU1_RSVD<115>")
	)
	(segment
		(start 118.32844 -266.406122)
		(end 118.32844 -266.941808)
		(width 0.12954)
		(layer "F.Cu")
		(net "CPU1_RSVD<115>")
	)
	(via
		(at 137.138156 -266.680442)
		(size 0.6604)
		(drill 0.3302)
		(layers "F.Cu" "B.Cu")
		(net "CPU1_RSVD<115>")
	)
	(via
		(at 118.32844 -266.941808)
		(size 0.4572)
		(drill 0.2032)
		(layers "F.Cu" "B.Cu")
		(net "CPU1_RSVD<115>")
	)
	(segment
		(start 136.385046 -266.56665)
		(end 137.138156 -266.680442)
		(width 0.0889)
		(layer "B.Cu")
		(net "CPU1_RSVD<115>")
	)
	(segment
		(start 118.32844 -266.941808)
		(end 118.572026 -266.698222)
		(width 0.0889)
		(layer "B.Cu")
		(net "CPU1_RSVD<115>")
	)
	(segment
		(start 135.432546 -266.617704)
		(end 135.44296 -266.6238)
		(width 0.0889)
		(layer "B.Cu")
		(net "CPU1_RSVD<115>")
	)
	(segment
		(start 124.154946 -266.617704)
		(end 124.169678 -266.62634)
		(width 0.0889)
		(layer "B.Cu")
		(net "CPU1_RSVD<115>")
	)
	(segment
		(start 129.793746 -266.617704)
		(end 129.808478 -266.62634)
		(width 0.0889)
		(layer "B.Cu")
		(net "CPU1_RSVD<115>")
	)
	(segment
		(start 119.070882 -266.6238)
		(end 119.081296 -266.617704)
		(width 0.0889)
		(layer "B.Cu")
		(net "CPU1_RSVD<115>")
	)
	(segment
		(start 134.492746 -266.617704)
		(end 134.507478 -266.62634)
		(width 0.0889)
		(layer "B.Cu")
		(net "CPU1_RSVD<115>")
	)
	(segment
		(start 128.853946 -266.617704)
		(end 128.868678 -266.62634)
		(width 0.0889)
		(layer "B.Cu")
		(net "CPU1_RSVD<115>")
	)
	(segment
		(start 127.914146 -266.617704)
		(end 127.928878 -266.62634)
		(width 0.0889)
		(layer "B.Cu")
		(net "CPU1_RSVD<115>")
	)
	(segment
		(start 118.572026 -266.698222)
		(end 118.579138 -266.698222)
		(width 0.0889)
		(layer "B.Cu")
		(net "CPU1_RSVD<115>")
	)
	(segment
		(start 122.275346 -266.617704)
		(end 122.290078 -266.62634)
		(width 0.0889)
		(layer "B.Cu")
		(net "CPU1_RSVD<115>")
	)
	(segment
		(start 130.733546 -266.617704)
		(end 130.748278 -266.62634)
		(width 0.0889)
		(layer "B.Cu")
		(net "CPU1_RSVD<115>")
	)
	(segment
		(start 133.552692 -266.617704)
		(end 133.563106 -266.6238)
		(width 0.0889)
		(layer "B.Cu")
		(net "CPU1_RSVD<115>")
	)
	(segment
		(start 126.974346 -266.617704)
		(end 126.989078 -266.62634)
		(width 0.0889)
		(layer "B.Cu")
		(net "CPU1_RSVD<115>")
	)
	(segment
		(start 125.094746 -266.617704)
		(end 125.10516 -266.6238)
		(width 0.0889)
		(layer "B.Cu")
		(net "CPU1_RSVD<115>")
	)
	(segment
		(start 136.185148 -266.56665)
		(end 136.385046 -266.56665)
		(width 0.0889)
		(layer "B.Cu")
		(net "CPU1_RSVD<115>")
	)
	(segment
		(start 119.455692 -266.617704)
		(end 119.466106 -266.6238)
		(width 0.0889)
		(layer "B.Cu")
		(net "CPU1_RSVD<115>")
	)
	(segment
		(start 123.215146 -266.617704)
		(end 123.229878 -266.62634)
		(width 0.0889)
		(layer "B.Cu")
		(net "CPU1_RSVD<115>")
	)
	(segment
		(start 121.335292 -266.617704)
		(end 121.345706 -266.6238)
		(width 0.0889)
		(layer "B.Cu")
		(net "CPU1_RSVD<115>")
	)
	(segment
		(start 131.673346 -266.617704)
		(end 131.68376 -266.6238)
		(width 0.0889)
		(layer "B.Cu")
		(net "CPU1_RSVD<115>")
	)
	(segment
		(start 126.034292 -266.617704)
		(end 126.044706 -266.6238)
		(width 0.0889)
		(layer "B.Cu")
		(net "CPU1_RSVD<115>")
	)
	(segment
		(start 120.395746 -266.617704)
		(end 120.40616 -266.6238)
		(width 0.0889)
		(layer "B.Cu")
		(net "CPU1_RSVD<115>")
	)
	(arc
		(start 118.822724 -266.693142)
		(mid 118.950797 -266.672777)
		(end 119.070882 -266.6238)
		(width 0.0889)
		(layer "B.Cu")
		(net "CPU1_RSVD<115>")
	)
	(arc
		(start 129.41935 -266.617704)
		(mid 129.606548 -266.567527)
		(end 129.793746 -266.617704)
		(width 0.0889)
		(layer "B.Cu")
		(net "CPU1_RSVD<115>")
	)
	(arc
		(start 128.868678 -266.62634)
		(mid 129.145153 -266.69366)
		(end 129.41935 -266.617704)
		(width 0.0889)
		(layer "B.Cu")
		(net "CPU1_RSVD<115>")
	)
	(arc
		(start 127.928878 -266.62634)
		(mid 128.205353 -266.69366)
		(end 128.47955 -266.617704)
		(width 0.0889)
		(layer "B.Cu")
		(net "CPU1_RSVD<115>")
	)
	(arc
		(start 120.02135 -266.617704)
		(mid 120.208548 -266.567527)
		(end 120.395746 -266.617704)
		(width 0.0889)
		(layer "B.Cu")
		(net "CPU1_RSVD<115>")
	)
	(arc
		(start 132.238496 -266.617704)
		(mid 132.425694 -266.567527)
		(end 132.612892 -266.617704)
		(width 0.0889)
		(layer "B.Cu")
		(net "CPU1_RSVD<115>")
	)
	(arc
		(start 124.169678 -266.62634)
		(mid 124.446153 -266.69366)
		(end 124.72035 -266.617704)
		(width 0.0889)
		(layer "B.Cu")
		(net "CPU1_RSVD<115>")
	)
	(arc
		(start 121.345706 -266.6238)
		(mid 121.624138 -266.693646)
		(end 121.90095 -266.617704)
		(width 0.0889)
		(layer "B.Cu")
		(net "CPU1_RSVD<115>")
	)
	(arc
		(start 125.10516 -266.6238)
		(mid 125.383338 -266.693523)
		(end 125.659896 -266.617704)
		(width 0.0889)
		(layer "B.Cu")
		(net "CPU1_RSVD<115>")
	)
	(arc
		(start 118.579138 -266.698222)
		(mid 118.700957 -266.696951)
		(end 118.822724 -266.693142)
		(width 0.0889)
		(layer "B.Cu")
		(net "CPU1_RSVD<115>")
	)
	(arc
		(start 119.081296 -266.617704)
		(mid 119.268494 -266.567527)
		(end 119.455692 -266.617704)
		(width 0.0889)
		(layer "B.Cu")
		(net "CPU1_RSVD<115>")
	)
	(arc
		(start 127.53975 -266.617704)
		(mid 127.726948 -266.567527)
		(end 127.914146 -266.617704)
		(width 0.0889)
		(layer "B.Cu")
		(net "CPU1_RSVD<115>")
	)
	(arc
		(start 133.563106 -266.6238)
		(mid 133.841538 -266.693646)
		(end 134.11835 -266.617704)
		(width 0.0889)
		(layer "B.Cu")
		(net "CPU1_RSVD<115>")
	)
	(arc
		(start 134.11835 -266.617704)
		(mid 134.305548 -266.567527)
		(end 134.492746 -266.617704)
		(width 0.0889)
		(layer "B.Cu")
		(net "CPU1_RSVD<115>")
	)
	(arc
		(start 133.178296 -266.617704)
		(mid 133.365494 -266.567527)
		(end 133.552692 -266.617704)
		(width 0.0889)
		(layer "B.Cu")
		(net "CPU1_RSVD<115>")
	)
	(arc
		(start 123.229878 -266.62634)
		(mid 123.506353 -266.69366)
		(end 123.78055 -266.617704)
		(width 0.0889)
		(layer "B.Cu")
		(net "CPU1_RSVD<115>")
	)
	(arc
		(start 126.989078 -266.62634)
		(mid 127.265553 -266.69366)
		(end 127.53975 -266.617704)
		(width 0.0889)
		(layer "B.Cu")
		(net "CPU1_RSVD<115>")
	)
	(arc
		(start 135.05815 -266.617704)
		(mid 135.245348 -266.567561)
		(end 135.432546 -266.617704)
		(width 0.0889)
		(layer "B.Cu")
		(net "CPU1_RSVD<115>")
	)
	(arc
		(start 120.40616 -266.6238)
		(mid 120.684338 -266.693523)
		(end 120.960896 -266.617704)
		(width 0.0889)
		(layer "B.Cu")
		(net "CPU1_RSVD<115>")
	)
	(arc
		(start 132.612892 -266.617704)
		(mid 132.895594 -266.69348)
		(end 133.178296 -266.617704)
		(width 0.0889)
		(layer "B.Cu")
		(net "CPU1_RSVD<115>")
	)
	(arc
		(start 130.748278 -266.62634)
		(mid 131.024753 -266.69366)
		(end 131.29895 -266.617704)
		(width 0.0889)
		(layer "B.Cu")
		(net "CPU1_RSVD<115>")
	)
	(arc
		(start 130.35915 -266.617704)
		(mid 130.546348 -266.567527)
		(end 130.733546 -266.617704)
		(width 0.0889)
		(layer "B.Cu")
		(net "CPU1_RSVD<115>")
	)
	(arc
		(start 126.044706 -266.6238)
		(mid 126.323138 -266.693646)
		(end 126.59995 -266.617704)
		(width 0.0889)
		(layer "B.Cu")
		(net "CPU1_RSVD<115>")
	)
	(arc
		(start 131.68376 -266.6238)
		(mid 131.961938 -266.693523)
		(end 132.238496 -266.617704)
		(width 0.0889)
		(layer "B.Cu")
		(net "CPU1_RSVD<115>")
	)
	(arc
		(start 134.507478 -266.62634)
		(mid 134.783953 -266.69366)
		(end 135.05815 -266.617704)
		(width 0.0889)
		(layer "B.Cu")
		(net "CPU1_RSVD<115>")
	)
	(arc
		(start 122.84075 -266.617704)
		(mid 123.027948 -266.567527)
		(end 123.215146 -266.617704)
		(width 0.0889)
		(layer "B.Cu")
		(net "CPU1_RSVD<115>")
	)
	(arc
		(start 126.59995 -266.617704)
		(mid 126.787148 -266.567527)
		(end 126.974346 -266.617704)
		(width 0.0889)
		(layer "B.Cu")
		(net "CPU1_RSVD<115>")
	)
	(arc
		(start 122.290078 -266.62634)
		(mid 122.566553 -266.69366)
		(end 122.84075 -266.617704)
		(width 0.0889)
		(layer "B.Cu")
		(net "CPU1_RSVD<115>")
	)
	(arc
		(start 123.78055 -266.617704)
		(mid 123.967748 -266.567527)
		(end 124.154946 -266.617704)
		(width 0.0889)
		(layer "B.Cu")
		(net "CPU1_RSVD<115>")
	)
	(arc
		(start 119.466106 -266.6238)
		(mid 119.744538 -266.693646)
		(end 120.02135 -266.617704)
		(width 0.0889)
		(layer "B.Cu")
		(net "CPU1_RSVD<115>")
	)
	(arc
		(start 135.997696 -266.617704)
		(mid 136.088058 -266.579837)
		(end 136.185148 -266.56665)
		(width 0.0889)
		(layer "B.Cu")
		(net "CPU1_RSVD<115>")
	)
	(arc
		(start 121.90095 -266.617704)
		(mid 122.088148 -266.567527)
		(end 122.275346 -266.617704)
		(width 0.0889)
		(layer "B.Cu")
		(net "CPU1_RSVD<115>")
	)
	(arc
		(start 129.808478 -266.62634)
		(mid 130.084953 -266.69366)
		(end 130.35915 -266.617704)
		(width 0.0889)
		(layer "B.Cu")
		(net "CPU1_RSVD<115>")
	)
	(arc
		(start 135.44296 -266.6238)
		(mid 135.721138 -266.693523)
		(end 135.997696 -266.617704)
		(width 0.0889)
		(layer "B.Cu")
		(net "CPU1_RSVD<115>")
	)
	(arc
		(start 124.72035 -266.617704)
		(mid 124.907548 -266.567527)
		(end 125.094746 -266.617704)
		(width 0.0889)
		(layer "B.Cu")
		(net "CPU1_RSVD<115>")
	)
	(arc
		(start 128.47955 -266.617704)
		(mid 128.666748 -266.567527)
		(end 128.853946 -266.617704)
		(width 0.0889)
		(layer "B.Cu")
		(net "CPU1_RSVD<115>")
	)
	(arc
		(start 125.659896 -266.617704)
		(mid 125.847094 -266.567527)
		(end 126.034292 -266.617704)
		(width 0.0889)
		(layer "B.Cu")
		(net "CPU1_RSVD<115>")
	)
	(arc
		(start 131.29895 -266.617704)
		(mid 131.486148 -266.567527)
		(end 131.673346 -266.617704)
		(width 0.0889)
		(layer "B.Cu")
		(net "CPU1_RSVD<115>")
	)
	(arc
		(start 120.960896 -266.617704)
		(mid 121.148094 -266.567527)
		(end 121.335292 -266.617704)
		(width 0.0889)
		(layer "B.Cu")
		(net "CPU1_RSVD<115>")
	)
	(segment
		(start 117.859048 -267.219938)
		(end 117.858794 -267.220192)
		(width 0.12954)
		(layer "F.Cu")
		(net "CPU1_RSVD<110>")
	)
	(segment
		(start 117.858794 -267.220192)
		(end 117.858794 -267.755878)
		(width 0.12954)
		(layer "F.Cu")
		(net "CPU1_RSVD<110>")
	)
	(via
		(at 117.858794 -267.755878)
		(size 0.4572)
		(drill 0.2032)
		(layers "F.Cu" "B.Cu")
		(net "CPU1_RSVD<110>")
	)
	(segment
		(start 117.749066 -230.086916)
		(end 117.748812 -230.086662)
		(width 0.12954)
		(layer "F.Cu")
		(net "CPU1_RSVD<107>")
	)
	(segment
		(start 117.749066 -230.622602)
		(end 117.749066 -230.086916)
		(width 0.12954)
		(layer "F.Cu")
		(net "CPU1_RSVD<107>")
	)
	(via
		(at 117.748812 -230.086662)
		(size 0.4572)
		(drill 0.2032)
		(layers "F.Cu" "B.Cu")
		(net "CPU1_RSVD<107>")
	)
	(segment
		(start 249.349768 -97.608644)
		(end 249.152664 -97.608644)
		(width 0.12954)
		(layer "F.Cu")
		(net "CLK_CK440_SMB_ADDR1")
	)
	(segment
		(start 249.674888 -97.933764)
		(end 249.349768 -97.608644)
		(width 0.12954)
		(layer "F.Cu")
		(net "CLK_CK440_SMB_ADDR1")
	)
	(segment
		(start 249.892058 -98.02368)
		(end 249.674888 -97.933764)
		(width 0.0889)
		(layer "F.Cu")
		(net "CLK_CK440_SMB_ADDR1")
	)
	(segment
		(start 251.377196 -98.02368)
		(end 249.892058 -98.02368)
		(width 0.0889)
		(layer "F.Cu")
		(net "CLK_CK440_SMB_ADDR1")
	)
	(segment
		(start 251.416566 -98.06305)
		(end 251.377196 -98.02368)
		(width 0.0889)
		(layer "F.Cu")
		(net "CLK_CK440_SMB_ADDR1")
	)
	(segment
		(start 252.557788 -98.06305)
		(end 251.416566 -98.06305)
		(width 0.0889)
		(layer "F.Cu")
		(net "CLK_CK440_SMB_ADDR1")
	)
	(via
		(at 247.402604 -101.106224)
		(size 0.6604)
		(drill 0.3302)
		(layers "F.Cu" "B.Cu")
		(net "CLK_CK440_SMB_ADDR1")
	)
	(via
		(at 249.152664 -97.608644)
		(size 0.508)
		(drill 0.254)
		(layers "F.Cu" "B.Cu")
		(net "CLK_CK440_SMB_ADDR1")
	)
	(segment
		(start 247.57888 -100.675948)
		(end 247.57888 -100.929948)
		(width 0.12954)
		(layer "B.Cu")
		(net "CLK_CK440_SMB_ADDR1")
	)
	(segment
		(start 248.46788 -98.293428)
		(end 248.46788 -99.786948)
		(width 0.12954)
		(layer "B.Cu")
		(net "CLK_CK440_SMB_ADDR1")
	)
	(segment
		(start 247.57888 -100.929948)
		(end 247.402604 -101.106224)
		(width 0.12954)
		(layer "B.Cu")
		(net "CLK_CK440_SMB_ADDR1")
	)
	(segment
		(start 247.381776 -101.127052)
		(end 246.235474 -101.127052)
		(width 0.12954)
		(layer "B.Cu")
		(net "CLK_CK440_SMB_ADDR1")
	)
	(segment
		(start 246.235474 -100.121212)
		(end 246.235474 -101.127052)
		(width 0.12954)
		(layer "B.Cu")
		(net "CLK_CK440_SMB_ADDR1")
	)
	(segment
		(start 247.402604 -101.106224)
		(end 247.381776 -101.127052)
		(width 0.12954)
		(layer "B.Cu")
		(net "CLK_CK440_SMB_ADDR1")
	)
	(segment
		(start 248.46788 -99.786948)
		(end 247.57888 -100.675948)
		(width 0.12954)
		(layer "B.Cu")
		(net "CLK_CK440_SMB_ADDR1")
	)
	(segment
		(start 249.152664 -97.608644)
		(end 248.46788 -98.293428)
		(width 0.12954)
		(layer "B.Cu")
		(net "CLK_CK440_SMB_ADDR1")
	)
	(segment
		(start 248.859548 -97.127568)
		(end 248.399046 -97.58807)
		(width 0.12954)
		(layer "F.Cu")
		(net "CLK_CK440_SMB_ADDR0")
	)
	(segment
		(start 250.14301 -97.813114)
		(end 249.457464 -97.127568)
		(width 0.12954)
		(layer "F.Cu")
		(net "CLK_CK440_SMB_ADDR0")
	)
	(segment
		(start 251.807726 -97.813114)
		(end 250.14301 -97.813114)
		(width 0.12954)
		(layer "F.Cu")
		(net "CLK_CK440_SMB_ADDR0")
	)
	(segment
		(start 249.457464 -97.127568)
		(end 248.859548 -97.127568)
		(width 0.12954)
		(layer "F.Cu")
		(net "CLK_CK440_SMB_ADDR0")
	)
	(via
		(at 248.399046 -97.58807)
		(size 0.508)
		(drill 0.254)
		(layers "F.Cu" "B.Cu")
		(net "CLK_CK440_SMB_ADDR0")
	)
	(segment
		(start 246.27713 -98.109024)
		(end 246.235474 -98.109024)
		(width 0.12954)
		(layer "B.Cu")
		(net "CLK_CK440_SMB_ADDR0")
	)
	(segment
		(start 247.381268 -98.605848)
		(end 246.773954 -98.605848)
		(width 0.12954)
		(layer "B.Cu")
		(net "CLK_CK440_SMB_ADDR0")
	)
	(segment
		(start 246.773954 -98.605848)
		(end 246.27713 -98.109024)
		(width 0.12954)
		(layer "B.Cu")
		(net "CLK_CK440_SMB_ADDR0")
	)
	(segment
		(start 246.235474 -98.109024)
		(end 246.235474 -99.136708)
		(width 0.12954)
		(layer "B.Cu")
		(net "CLK_CK440_SMB_ADDR0")
	)
	(segment
		(start 246.235474 -98.109024)
		(end 246.218456 -98.092006)
		(width 0.12954)
		(layer "B.Cu")
		(net "CLK_CK440_SMB_ADDR0")
	)
	(segment
		(start 248.399046 -97.58807)
		(end 247.381268 -98.605848)
		(width 0.12954)
		(layer "B.Cu")
		(net "CLK_CK440_SMB_ADDR0")
	)
	(segment
		(start 215.90381 -22.904704)
		(end 215.90381 -22.184614)
		(width 0.12954)
		(layer "F.Cu")
		(net "CLK_50M_RMII_R")
	)
	(segment
		(start 215.90381 -21.039328)
		(end 215.552274 -20.687792)
		(width 0.12954)
		(layer "F.Cu")
		(net "CLK_50M_RMII_R")
	)
	(segment
		(start 215.90381 -22.184614)
		(end 215.90381 -21.039328)
		(width 0.12954)
		(layer "F.Cu")
		(net "CLK_50M_RMII_R")
	)
	(segment
		(start 215.552274 -20.687792)
		(end 215.31961 -20.687792)
		(width 0.12954)
		(layer "F.Cu")
		(net "CLK_50M_RMII_R")
	)
	(via
		(at 215.90381 -22.184614)
		(size 0.508)
		(drill 0.254)
		(layers "F.Cu" "B.Cu")
		(net "CLK_50M_RMII_R")
	)
	(segment
		(start 168.666668 -17.466056)
		(end 168.666668 -17.99336)
		(width 0.12954)
		(layer "F.Cu")
		(net "CLK_50M_RMII_BMC_OCP")
	)
	(segment
		(start 212.6615 -22.974554)
		(end 212.6615 -23.678134)
		(width 0.12954)
		(layer "F.Cu")
		(net "CLK_50M_RMII_BMC_OCP")
	)
	(segment
		(start 168.666668 -17.99336)
		(end 168.255696 -18.983452)
		(width 0.12954)
		(layer "F.Cu")
		(net "CLK_50M_RMII_BMC_OCP")
	)
	(segment
		(start 168.666922 -16.550132)
		(end 168.666922 -17.465802)
		(width 0.12954)
		(layer "F.Cu")
		(net "CLK_50M_RMII_BMC_OCP")
	)
	(segment
		(start 168.255696 -18.983452)
		(end 168.0464 -19.192748)
		(width 0.12954)
		(layer "F.Cu")
		(net "CLK_50M_RMII_BMC_OCP")
	)
	(segment
		(start 168.666922 -17.465802)
		(end 168.666668 -17.466056)
		(width 0.12954)
		(layer "F.Cu")
		(net "CLK_50M_RMII_BMC_OCP")
	)
	(via
		(at 168.0464 -19.192748)
		(size 0.508)
		(drill 0.254)
		(layers "F.Cu" "B.Cu")
		(net "CLK_50M_RMII_BMC_OCP")
	)
	(via
		(at 212.6615 -23.678134)
		(size 0.508)
		(drill 0.254)
		(layers "F.Cu" "B.Cu")
		(net "CLK_50M_RMII_BMC_OCP")
	)
	(segment
		(start 184.818274 -13.009118)
		(end 184.437274 -13.009118)
		(width 0.127)
		(layer "In11.Cu")
		(net "CLK_50M_RMII_BMC_OCP")
	)
	(segment
		(start 167.245538 -14.153134)
		(end 167.118538 -14.026134)
		(width 0.127)
		(layer "In11.Cu")
		(net "CLK_50M_RMII_BMC_OCP")
	)
	(segment
		(start 178.722274 -13.845794)
		(end 178.595274 -13.718794)
		(width 0.127)
		(layer "In11.Cu")
		(net "CLK_50M_RMII_BMC_OCP")
	)
	(segment
		(start 207.993742 -15.112492)
		(end 207.993742 -14.933168)
		(width 0.127)
		(layer "In11.Cu")
		(net "CLK_50M_RMII_BMC_OCP")
	)
	(segment
		(start 181.897274 -13.009118)
		(end 181.770274 -13.136118)
		(width 0.127)
		(layer "In11.Cu")
		(net "CLK_50M_RMII_BMC_OCP")
	)
	(segment
		(start 200.36155 -13.972794)
		(end 200.36155 -16.493744)
		(width 0.127)
		(layer "In11.Cu")
		(net "CLK_50M_RMII_BMC_OCP")
	)
	(segment
		(start 180.500274 -13.136118)
		(end 180.500274 -13.718794)
		(width 0.127)
		(layer "In11.Cu")
		(net "CLK_50M_RMII_BMC_OCP")
	)
	(segment
		(start 167.9448 -15.738348)
		(end 167.9448 -16.248888)
		(width 0.127)
		(layer "In11.Cu")
		(net "CLK_50M_RMII_BMC_OCP")
	)
	(segment
		(start 207.993742 -14.933168)
		(end 206.906368 -13.845794)
		(width 0.127)
		(layer "In11.Cu")
		(net "CLK_50M_RMII_BMC_OCP")
	)
	(segment
		(start 187.358274 -13.009118)
		(end 186.977274 -13.009118)
		(width 0.127)
		(layer "In11.Cu")
		(net "CLK_50M_RMII_BMC_OCP")
	)
	(segment
		(start 183.040274 -13.136118)
		(end 183.040274 -13.718794)
		(width 0.127)
		(layer "In11.Cu")
		(net "CLK_50M_RMII_BMC_OCP")
	)
	(segment
		(start 211.869782 -19.541744)
		(end 211.869782 -18.809208)
		(width 0.127)
		(layer "In11.Cu")
		(net "CLK_50M_RMII_BMC_OCP")
	)
	(segment
		(start 199.85355 -16.620744)
		(end 199.72655 -16.493744)
		(width 0.127)
		(layer "In11.Cu")
		(net "CLK_50M_RMII_BMC_OCP")
	)
	(segment
		(start 179.738274 -13.009118)
		(end 179.357274 -13.009118)
		(width 0.127)
		(layer "In11.Cu")
		(net "CLK_50M_RMII_BMC_OCP")
	)
	(segment
		(start 179.230274 -13.718794)
		(end 179.103274 -13.845794)
		(width 0.127)
		(layer "In11.Cu")
		(net "CLK_50M_RMII_BMC_OCP")
	)
	(segment
		(start 198.96455 -16.620744)
		(end 198.58355 -16.620744)
		(width 0.127)
		(layer "In11.Cu")
		(net "CLK_50M_RMII_BMC_OCP")
	)
	(segment
		(start 210.47456 -21.991066)
		(end 210.47456 -21.610066)
		(width 0.127)
		(layer "In11.Cu")
		(net "CLK_50M_RMII_BMC_OCP")
	)
	(segment
		(start 211.742782 -21.470366)
		(end 211.869782 -21.343366)
		(width 0.127)
		(layer "In11.Cu")
		(net "CLK_50M_RMII_BMC_OCP")
	)
	(segment
		(start 197.69455 -16.620744)
		(end 197.31355 -16.620744)
		(width 0.127)
		(layer "In11.Cu")
		(net "CLK_50M_RMII_BMC_OCP")
	)
	(segment
		(start 174.785274 -13.136118)
		(end 174.658274 -13.009118)
		(width 0.127)
		(layer "In11.Cu")
		(net "CLK_50M_RMII_BMC_OCP")
	)
	(segment
		(start 184.437274 -13.009118)
		(end 184.310274 -13.136118)
		(width 0.127)
		(layer "In11.Cu")
		(net "CLK_50M_RMII_BMC_OCP")
	)
	(segment
		(start 166.356538 -14.153134)
		(end 165.050978 -14.153134)
		(width 0.127)
		(layer "In11.Cu")
		(net "CLK_50M_RMII_BMC_OCP")
	)
	(segment
		(start 169.286682 -16.375888)
		(end 169.413682 -16.502888)
		(width 0.127)
		(layer "In11.Cu")
		(net "CLK_50M_RMII_BMC_OCP")
	)
	(segment
		(start 181.770274 -13.136118)
		(end 181.770274 -13.718794)
		(width 0.127)
		(layer "In11.Cu")
		(net "CLK_50M_RMII_BMC_OCP")
	)
	(segment
		(start 195.28155 -13.972794)
		(end 195.28155 -16.493744)
		(width 0.127)
		(layer "In11.Cu")
		(net "CLK_50M_RMII_BMC_OCP")
	)
	(segment
		(start 172.880274 -13.718794)
		(end 172.753274 -13.845794)
		(width 0.127)
		(layer "In11.Cu")
		(net "CLK_50M_RMII_BMC_OCP")
	)
	(segment
		(start 206.524352 -16.582136)
		(end 207.993742 -15.112492)
		(width 0.127)
		(layer "In11.Cu")
		(net "CLK_50M_RMII_BMC_OCP")
	)
	(segment
		(start 177.960274 -13.136118)
		(end 177.960274 -13.718794)
		(width 0.127)
		(layer "In11.Cu")
		(net "CLK_50M_RMII_BMC_OCP")
	)
	(segment
		(start 190.025274 -13.136118)
		(end 189.898274 -13.009118)
		(width 0.127)
		(layer "In11.Cu")
		(net "CLK_50M_RMII_BMC_OCP")
	)
	(segment
		(start 196.55155 -16.493744)
		(end 196.42455 -16.620744)
		(width 0.127)
		(layer "In11.Cu")
		(net "CLK_50M_RMII_BMC_OCP")
	)
	(segment
		(start 177.833274 -13.845794)
		(end 177.452274 -13.845794)
		(width 0.127)
		(layer "In11.Cu")
		(net "CLK_50M_RMII_BMC_OCP")
	)
	(segment
		(start 209.667856 -19.72564)
		(end 209.488532 -19.72564)
		(width 0.127)
		(layer "In11.Cu")
		(net "CLK_50M_RMII_BMC_OCP")
	)
	(segment
		(start 164.826188 -20.01139)
		(end 165.569646 -20.754848)
		(width 0.127)
		(layer "In11.Cu")
		(net "CLK_50M_RMII_BMC_OCP")
	)
	(segment
		(start 209.488532 -19.72564)
		(end 209.218784 -19.455892)
		(width 0.127)
		(layer "In11.Cu")
		(net "CLK_50M_RMII_BMC_OCP")
	)
	(segment
		(start 211.378292 -20.176744)
		(end 211.378292 -19.795744)
		(width 0.127)
		(layer "In11.Cu")
		(net "CLK_50M_RMII_BMC_OCP")
	)
	(segment
		(start 179.992274 -13.845794)
		(end 179.865274 -13.718794)
		(width 0.127)
		(layer "In11.Cu")
		(net "CLK_50M_RMII_BMC_OCP")
	)
	(segment
		(start 198.45655 -13.972794)
		(end 198.32955 -13.845794)
		(width 0.127)
		(layer "In11.Cu")
		(net "CLK_50M_RMII_BMC_OCP")
	)
	(segment
		(start 200.36155 -16.493744)
		(end 200.23455 -16.620744)
		(width 0.127)
		(layer "In11.Cu")
		(net "CLK_50M_RMII_BMC_OCP")
	)
	(segment
		(start 200.99655 -13.972794)
		(end 200.86955 -13.845794)
		(width 0.127)
		(layer "In11.Cu")
		(net "CLK_50M_RMII_BMC_OCP")
	)
	(segment
		(start 188.882274 -13.845794)
		(end 188.755274 -13.718794)
		(width 0.127)
		(layer "In11.Cu")
		(net "CLK_50M_RMII_BMC_OCP")
	)
	(segment
		(start 206.906368 -13.845794)
		(end 205.56855 -13.845794)
		(width 0.127)
		(layer "In11.Cu")
		(net "CLK_50M_RMII_BMC_OCP")
	)
	(segment
		(start 181.008274 -13.009118)
		(end 180.627274 -13.009118)
		(width 0.127)
		(layer "In11.Cu")
		(net "CLK_50M_RMII_BMC_OCP")
	)
	(segment
		(start 186.342274 -13.845794)
		(end 186.215274 -13.718794)
		(width 0.127)
		(layer "In11.Cu")
		(net "CLK_50M_RMII_BMC_OCP")
	)
	(segment
		(start 183.675274 -13.718794)
		(end 183.675274 -13.136118)
		(width 0.127)
		(layer "In11.Cu")
		(net "CLK_50M_RMII_BMC_OCP")
	)
	(segment
		(start 189.517274 -13.009118)
		(end 189.390274 -13.136118)
		(width 0.127)
		(layer "In11.Cu")
		(net "CLK_50M_RMII_BMC_OCP")
	)
	(segment
		(start 175.547274 -13.009118)
		(end 175.420274 -13.136118)
		(width 0.127)
		(layer "In11.Cu")
		(net "CLK_50M_RMII_BMC_OCP")
	)
	(segment
		(start 200.86955 -13.845794)
		(end 200.48855 -13.845794)
		(width 0.127)
		(layer "In11.Cu")
		(net "CLK_50M_RMII_BMC_OCP")
	)
	(segment
		(start 186.215274 -13.136118)
		(end 186.088274 -13.009118)
		(width 0.127)
		(layer "In11.Cu")
		(net "CLK_50M_RMII_BMC_OCP")
	)
	(segment
		(start 173.007274 -13.009118)
		(end 172.880274 -13.136118)
		(width 0.127)
		(layer "In11.Cu")
		(net "CLK_50M_RMII_BMC_OCP")
	)
	(segment
		(start 176.563274 -13.845794)
		(end 176.182274 -13.845794)
		(width 0.127)
		(layer "In11.Cu")
		(net "CLK_50M_RMII_BMC_OCP")
	)
	(segment
		(start 174.023274 -13.845794)
		(end 173.642274 -13.845794)
		(width 0.127)
		(layer "In11.Cu")
		(net "CLK_50M_RMII_BMC_OCP")
	)
	(segment
		(start 185.707274 -13.009118)
		(end 185.580274 -13.136118)
		(width 0.127)
		(layer "In11.Cu")
		(net "CLK_50M_RMII_BMC_OCP")
	)
	(segment
		(start 197.18655 -13.972794)
		(end 197.05955 -13.845794)
		(width 0.127)
		(layer "In11.Cu")
		(net "CLK_50M_RMII_BMC_OCP")
	)
	(segment
		(start 178.087274 -13.009118)
		(end 177.960274 -13.136118)
		(width 0.127)
		(layer "In11.Cu")
		(net "CLK_50M_RMII_BMC_OCP")
	)
	(segment
		(start 208.32064 -18.557748)
		(end 208.32064 -18.378424)
		(width 0.127)
		(layer "In11.Cu")
		(net "CLK_50M_RMII_BMC_OCP")
	)
	(segment
		(start 182.913274 -13.845794)
		(end 182.532274 -13.845794)
		(width 0.127)
		(layer "In11.Cu")
		(net "CLK_50M_RMII_BMC_OCP")
	)
	(segment
		(start 186.850274 -13.136118)
		(end 186.850274 -13.718794)
		(width 0.127)
		(layer "In11.Cu")
		(net "CLK_50M_RMII_BMC_OCP")
	)
	(segment
		(start 176.182274 -13.845794)
		(end 176.055274 -13.718794)
		(width 0.127)
		(layer "In11.Cu")
		(net "CLK_50M_RMII_BMC_OCP")
	)
	(segment
		(start 207.422496 -17.659604)
		(end 207.422496 -17.48028)
		(width 0.127)
		(layer "In11.Cu")
		(net "CLK_50M_RMII_BMC_OCP")
	)
	(segment
		(start 209.79003 -16.729456)
		(end 209.520282 -16.459708)
		(width 0.127)
		(layer "In11.Cu")
		(net "CLK_50M_RMII_BMC_OCP")
	)
	(segment
		(start 209.218784 -19.455892)
		(end 209.218784 -19.276568)
		(width 0.127)
		(layer "In11.Cu")
		(net "CLK_50M_RMII_BMC_OCP")
	)
	(segment
		(start 190.025274 -13.718794)
		(end 190.025274 -13.136118)
		(width 0.127)
		(layer "In11.Cu")
		(net "CLK_50M_RMII_BMC_OCP")
	)
	(segment
		(start 167.753538 -14.026134)
		(end 167.626538 -14.153134)
		(width 0.127)
		(layer "In11.Cu")
		(net "CLK_50M_RMII_BMC_OCP")
	)
	(segment
		(start 211.869782 -22.886416)
		(end 211.869782 -22.232366)
		(width 0.127)
		(layer "In11.Cu")
		(net "CLK_50M_RMII_BMC_OCP")
	)
	(segment
		(start 197.18655 -16.493744)
		(end 197.18655 -13.972794)
		(width 0.127)
		(layer "In11.Cu")
		(net "CLK_50M_RMII_BMC_OCP")
	)
	(segment
		(start 173.388274 -13.009118)
		(end 173.007274 -13.009118)
		(width 0.127)
		(layer "In11.Cu")
		(net "CLK_50M_RMII_BMC_OCP")
	)
	(segment
		(start 201.12355 -16.620744)
		(end 200.99655 -16.493744)
		(width 0.127)
		(layer "In11.Cu")
		(net "CLK_50M_RMII_BMC_OCP")
	)
	(segment
		(start 167.880538 -12.964922)
		(end 167.753538 -13.091922)
		(width 0.127)
		(layer "In11.Cu")
		(net "CLK_50M_RMII_BMC_OCP")
	)
	(segment
		(start 166.8018 -16.375888)
		(end 167.1828 -16.375888)
		(width 0.127)
		(layer "In11.Cu")
		(net "CLK_50M_RMII_BMC_OCP")
	)
	(segment
		(start 209.520282 -16.459708)
		(end 209.340958 -16.459708)
		(width 0.127)
		(layer "In11.Cu")
		(net "CLK_50M_RMII_BMC_OCP")
	)
	(segment
		(start 179.103274 -13.845794)
		(end 178.722274 -13.845794)
		(width 0.127)
		(layer "In11.Cu")
		(net "CLK_50M_RMII_BMC_OCP")
	)
	(segment
		(start 208.622138 -15.561564)
		(end 208.442814 -15.561564)
		(width 0.127)
		(layer "In11.Cu")
		(net "CLK_50M_RMII_BMC_OCP")
	)
	(segment
		(start 167.118538 -14.026134)
		(end 167.118538 -13.091922)
		(width 0.127)
		(layer "In11.Cu")
		(net "CLK_50M_RMII_BMC_OCP")
	)
	(segment
		(start 199.72655 -13.972794)
		(end 199.59955 -13.845794)
		(width 0.127)
		(layer "In11.Cu")
		(net "CLK_50M_RMII_BMC_OCP")
	)
	(segment
		(start 175.420274 -13.136118)
		(end 175.420274 -13.718794)
		(width 0.127)
		(layer "In11.Cu")
		(net "CLK_50M_RMII_BMC_OCP")
	)
	(segment
		(start 197.94855 -13.845794)
		(end 197.82155 -13.972794)
		(width 0.127)
		(layer "In11.Cu")
		(net "CLK_50M_RMII_BMC_OCP")
	)
	(segment
		(start 208.590388 -18.827496)
		(end 208.32064 -18.557748)
		(width 0.127)
		(layer "In11.Cu")
		(net "CLK_50M_RMII_BMC_OCP")
	)
	(segment
		(start 199.09155 -13.972794)
		(end 199.09155 -16.493744)
		(width 0.127)
		(layer "In11.Cu")
		(net "CLK_50M_RMII_BMC_OCP")
	)
	(segment
		(start 176.690274 -13.718794)
		(end 176.563274 -13.845794)
		(width 0.127)
		(layer "In11.Cu")
		(net "CLK_50M_RMII_BMC_OCP")
	)
	(segment
		(start 206.973424 -17.031208)
		(end 206.7941 -17.031208)
		(width 0.127)
		(layer "In11.Cu")
		(net "CLK_50M_RMII_BMC_OCP")
	)
	(segment
		(start 168.388538 -14.026134)
		(end 168.388538 -13.091922)
		(width 0.127)
		(layer "In11.Cu")
		(net "CLK_50M_RMII_BMC_OCP")
	)
	(segment
		(start 178.595274 -13.136118)
		(end 178.468274 -13.009118)
		(width 0.127)
		(layer "In11.Cu")
		(net "CLK_50M_RMII_BMC_OCP")
	)
	(segment
		(start 175.420274 -13.718794)
		(end 175.293274 -13.845794)
		(width 0.127)
		(layer "In11.Cu")
		(net "CLK_50M_RMII_BMC_OCP")
	)
	(segment
		(start 188.755274 -13.136118)
		(end 188.628274 -13.009118)
		(width 0.127)
		(layer "In11.Cu")
		(net "CLK_50M_RMII_BMC_OCP")
	)
	(segment
		(start 204.04455 -16.620744)
		(end 203.66355 -16.620744)
		(width 0.127)
		(layer "In11.Cu")
		(net "CLK_50M_RMII_BMC_OCP")
	)
	(segment
		(start 183.167274 -13.009118)
		(end 183.040274 -13.136118)
		(width 0.127)
		(layer "In11.Cu")
		(net "CLK_50M_RMII_BMC_OCP")
	)
	(segment
		(start 205.44155 -13.972794)
		(end 205.44155 -16.493744)
		(width 0.127)
		(layer "In11.Cu")
		(net "CLK_50M_RMII_BMC_OCP")
	)
	(segment
		(start 169.658538 -13.091922)
		(end 169.531538 -12.964922)
		(width 0.127)
		(layer "In11.Cu")
		(net "CLK_50M_RMII_BMC_OCP")
	)
	(segment
		(start 188.120274 -13.136118)
		(end 188.120274 -13.718794)
		(width 0.127)
		(layer "In11.Cu")
		(net "CLK_50M_RMII_BMC_OCP")
	)
	(segment
		(start 167.118538 -13.091922)
		(end 166.991538 -12.964922)
		(width 0.127)
		(layer "In11.Cu")
		(net "CLK_50M_RMII_BMC_OCP")
	)
	(segment
		(start 197.31355 -16.620744)
		(end 197.18655 -16.493744)
		(width 0.127)
		(layer "In11.Cu")
		(net "CLK_50M_RMII_BMC_OCP")
	)
	(segment
		(start 202.77455 -16.620744)
		(end 202.39355 -16.620744)
		(width 0.127)
		(layer "In11.Cu")
		(net "CLK_50M_RMII_BMC_OCP")
	)
	(segment
		(start 202.13955 -13.845794)
		(end 201.75855 -13.845794)
		(width 0.127)
		(layer "In11.Cu")
		(net "CLK_50M_RMII_BMC_OCP")
	)
	(segment
		(start 180.627274 -13.009118)
		(end 180.500274 -13.136118)
		(width 0.127)
		(layer "In11.Cu")
		(net "CLK_50M_RMII_BMC_OCP")
	)
	(segment
		(start 199.09155 -16.493744)
		(end 198.96455 -16.620744)
		(width 0.127)
		(layer "In11.Cu")
		(net "CLK_50M_RMII_BMC_OCP")
	)
	(segment
		(start 189.390274 -13.136118)
		(end 189.390274 -13.718794)
		(width 0.127)
		(layer "In11.Cu")
		(net "CLK_50M_RMII_BMC_OCP")
	)
	(segment
		(start 179.865274 -13.718794)
		(end 179.865274 -13.136118)
		(width 0.127)
		(layer "In11.Cu")
		(net "CLK_50M_RMII_BMC_OCP")
	)
	(segment
		(start 167.3098 -16.248888)
		(end 167.3098 -15.738348)
		(width 0.127)
		(layer "In11.Cu")
		(net "CLK_50M_RMII_BMC_OCP")
	)
	(segment
		(start 169.413682 -16.502888)
		(end 169.413682 -16.883888)
		(width 0.127)
		(layer "In11.Cu")
		(net "CLK_50M_RMII_BMC_OCP")
	)
	(segment
		(start 204.17155 -16.493744)
		(end 204.04455 -16.620744)
		(width 0.127)
		(layer "In11.Cu")
		(net "CLK_50M_RMII_BMC_OCP")
	)
	(segment
		(start 167.3098 -15.738348)
		(end 167.4368 -15.611348)
		(width 0.127)
		(layer "In11.Cu")
		(net "CLK_50M_RMII_BMC_OCP")
	)
	(segment
		(start 211.742782 -22.105366)
		(end 210.58886 -22.105366)
		(width 0.127)
		(layer "In11.Cu")
		(net "CLK_50M_RMII_BMC_OCP")
	)
	(segment
		(start 164.953188 -16.375888)
		(end 165.9128 -16.375888)
		(width 0.127)
		(layer "In11.Cu")
		(net "CLK_50M_RMII_BMC_OCP")
	)
	(segment
		(start 195.78955 -13.845794)
		(end 195.40855 -13.845794)
		(width 0.127)
		(layer "In11.Cu")
		(net "CLK_50M_RMII_BMC_OCP")
	)
	(segment
		(start 178.595274 -13.718794)
		(end 178.595274 -13.136118)
		(width 0.127)
		(layer "In11.Cu")
		(net "CLK_50M_RMII_BMC_OCP")
	)
	(segment
		(start 177.452274 -13.845794)
		(end 177.325274 -13.718794)
		(width 0.127)
		(layer "In11.Cu")
		(net "CLK_50M_RMII_BMC_OCP")
	)
	(segment
		(start 167.753538 -13.091922)
		(end 167.753538 -14.026134)
		(width 0.127)
		(layer "In11.Cu")
		(net "CLK_50M_RMII_BMC_OCP")
	)
	(segment
		(start 167.8178 -15.611348)
		(end 167.9448 -15.738348)
		(width 0.127)
		(layer "In11.Cu")
		(net "CLK_50M_RMII_BMC_OCP")
	)
	(segment
		(start 184.945274 -13.136118)
		(end 184.818274 -13.009118)
		(width 0.127)
		(layer "In11.Cu")
		(net "CLK_50M_RMII_BMC_OCP")
	)
	(segment
		(start 211.505292 -20.303744)
		(end 211.378292 -20.176744)
		(width 0.127)
		(layer "In11.Cu")
		(net "CLK_50M_RMII_BMC_OCP")
	)
	(segment
		(start 167.626538 -14.153134)
		(end 167.245538 -14.153134)
		(width 0.127)
		(layer "In11.Cu")
		(net "CLK_50M_RMII_BMC_OCP")
	)
	(segment
		(start 186.977274 -13.009118)
		(end 186.850274 -13.136118)
		(width 0.127)
		(layer "In11.Cu")
		(net "CLK_50M_RMII_BMC_OCP")
	)
	(segment
		(start 208.442814 -15.561564)
		(end 206.973424 -17.031208)
		(width 0.127)
		(layer "In11.Cu")
		(net "CLK_50M_RMII_BMC_OCP")
	)
	(segment
		(start 204.80655 -13.972794)
		(end 204.67955 -13.845794)
		(width 0.127)
		(layer "In11.Cu")
		(net "CLK_50M_RMII_BMC_OCP")
	)
	(segment
		(start 201.50455 -16.620744)
		(end 201.12355 -16.620744)
		(width 0.127)
		(layer "In11.Cu")
		(net "CLK_50M_RMII_BMC_OCP")
	)
	(segment
		(start 166.6748 -15.738348)
		(end 166.6748 -16.248888)
		(width 0.127)
		(layer "In11.Cu")
		(net "CLK_50M_RMII_BMC_OCP")
	)
	(segment
		(start 173.515274 -13.718794)
		(end 173.515274 -13.136118)
		(width 0.127)
		(layer "In11.Cu")
		(net "CLK_50M_RMII_BMC_OCP")
	)
	(segment
		(start 169.531538 -12.964922)
		(end 169.150538 -12.964922)
		(width 0.127)
		(layer "In11.Cu")
		(net "CLK_50M_RMII_BMC_OCP")
	)
	(segment
		(start 198.32955 -13.845794)
		(end 197.94855 -13.845794)
		(width 0.127)
		(layer "In11.Cu")
		(net "CLK_50M_RMII_BMC_OCP")
	)
	(segment
		(start 168.0464 -19.852894)
		(end 168.0464 -19.192748)
		(width 0.127)
		(layer "In11.Cu")
		(net "CLK_50M_RMII_BMC_OCP")
	)
	(segment
		(start 195.40855 -13.845794)
		(end 195.28155 -13.972794)
		(width 0.127)
		(layer "In11.Cu")
		(net "CLK_50M_RMII_BMC_OCP")
	)
	(segment
		(start 166.6748 -16.248888)
		(end 166.8018 -16.375888)
		(width 0.127)
		(layer "In11.Cu")
		(net "CLK_50M_RMII_BMC_OCP")
	)
	(segment
		(start 177.325274 -13.136118)
		(end 177.198274 -13.009118)
		(width 0.127)
		(layer "In11.Cu")
		(net "CLK_50M_RMII_BMC_OCP")
	)
	(segment
		(start 209.79003 -16.90878)
		(end 209.79003 -16.729456)
		(width 0.127)
		(layer "In11.Cu")
		(net "CLK_50M_RMII_BMC_OCP")
	)
	(segment
		(start 207.422496 -17.48028)
		(end 208.891886 -16.010636)
		(width 0.127)
		(layer "In11.Cu")
		(net "CLK_50M_RMII_BMC_OCP")
	)
	(segment
		(start 184.310274 -13.136118)
		(end 184.310274 -13.718794)
		(width 0.127)
		(layer "In11.Cu")
		(net "CLK_50M_RMII_BMC_OCP")
	)
	(segment
		(start 174.785274 -13.718794)
		(end 174.785274 -13.136118)
		(width 0.127)
		(layer "In11.Cu")
		(net "CLK_50M_RMII_BMC_OCP")
	)
	(segment
		(start 175.293274 -13.845794)
		(end 174.912274 -13.845794)
		(width 0.127)
		(layer "In11.Cu")
		(net "CLK_50M_RMII_BMC_OCP")
	)
	(segment
		(start 208.769712 -18.827496)
		(end 208.590388 -18.827496)
		(width 0.127)
		(layer "In11.Cu")
		(net "CLK_50M_RMII_BMC_OCP")
	)
	(segment
		(start 203.40955 -13.845794)
		(end 203.02855 -13.845794)
		(width 0.127)
		(layer "In11.Cu")
		(net "CLK_50M_RMII_BMC_OCP")
	)
	(segment
		(start 196.55155 -13.972794)
		(end 196.55155 -16.493744)
		(width 0.127)
		(layer "In11.Cu")
		(net "CLK_50M_RMII_BMC_OCP")
	)
	(segment
		(start 208.891886 -15.831312)
		(end 208.622138 -15.561564)
		(width 0.127)
		(layer "In11.Cu")
		(net "CLK_50M_RMII_BMC_OCP")
	)
	(segment
		(start 168.896538 -14.153134)
		(end 168.515538 -14.153134)
		(width 0.127)
		(layer "In11.Cu")
		(net "CLK_50M_RMII_BMC_OCP")
	)
	(segment
		(start 210.239102 -17.357852)
		(end 208.769712 -18.827496)
		(width 0.127)
		(layer "In11.Cu")
		(net "CLK_50M_RMII_BMC_OCP")
	)
	(segment
		(start 204.93355 -16.620744)
		(end 204.80655 -16.493744)
		(width 0.127)
		(layer "In11.Cu")
		(net "CLK_50M_RMII_BMC_OCP")
	)
	(segment
		(start 167.9448 -16.248888)
		(end 168.0718 -16.375888)
		(width 0.127)
		(layer "In11.Cu")
		(net "CLK_50M_RMII_BMC_OCP")
	)
	(segment
		(start 211.31657 -18.255996)
		(end 211.137246 -18.255996)
		(width 0.127)
		(layer "In11.Cu")
		(net "CLK_50M_RMII_BMC_OCP")
	)
	(segment
		(start 199.72655 -16.493744)
		(end 199.72655 -13.972794)
		(width 0.127)
		(layer "In11.Cu")
		(net "CLK_50M_RMII_BMC_OCP")
	)
	(segment
		(start 211.505292 -19.668744)
		(end 211.742782 -19.668744)
		(width 0.127)
		(layer "In11.Cu")
		(net "CLK_50M_RMII_BMC_OCP")
	)
	(segment
		(start 202.90155 -13.972794)
		(end 202.90155 -16.493744)
		(width 0.127)
		(layer "In11.Cu")
		(net "CLK_50M_RMII_BMC_OCP")
	)
	(segment
		(start 211.869782 -21.343366)
		(end 211.869782 -20.430744)
		(width 0.127)
		(layer "In11.Cu")
		(net "CLK_50M_RMII_BMC_OCP")
	)
	(segment
		(start 198.45655 -16.493744)
		(end 198.45655 -13.972794)
		(width 0.127)
		(layer "In11.Cu")
		(net "CLK_50M_RMII_BMC_OCP")
	)
	(segment
		(start 186.215274 -13.718794)
		(end 186.215274 -13.136118)
		(width 0.127)
		(layer "In11.Cu")
		(net "CLK_50M_RMII_BMC_OCP")
	)
	(segment
		(start 209.218784 -19.276568)
		(end 210.688174 -17.806924)
		(width 0.127)
		(layer "In11.Cu")
		(net "CLK_50M_RMII_BMC_OCP")
	)
	(segment
		(start 211.137246 -18.255996)
		(end 209.667856 -19.72564)
		(width 0.127)
		(layer "In11.Cu")
		(net "CLK_50M_RMII_BMC_OCP")
	)
	(segment
		(start 211.869782 -18.809208)
		(end 211.31657 -18.255996)
		(width 0.127)
		(layer "In11.Cu")
		(net "CLK_50M_RMII_BMC_OCP")
	)
	(segment
		(start 197.05955 -13.845794)
		(end 196.67855 -13.845794)
		(width 0.127)
		(layer "In11.Cu")
		(net "CLK_50M_RMII_BMC_OCP")
	)
	(segment
		(start 172.880274 -13.136118)
		(end 172.880274 -13.718794)
		(width 0.127)
		(layer "In11.Cu")
		(net "CLK_50M_RMII_BMC_OCP")
	)
	(segment
		(start 190.152274 -13.845794)
		(end 190.025274 -13.718794)
		(width 0.127)
		(layer "In11.Cu")
		(net "CLK_50M_RMII_BMC_OCP")
	)
	(segment
		(start 169.286682 -17.010888)
		(end 164.953188 -17.010888)
		(width 0.127)
		(layer "In11.Cu")
		(net "CLK_50M_RMII_BMC_OCP")
	)
	(segment
		(start 168.388538 -13.091922)
		(end 168.261538 -12.964922)
		(width 0.127)
		(layer "In11.Cu")
		(net "CLK_50M_RMII_BMC_OCP")
	)
	(segment
		(start 169.658538 -14.026134)
		(end 169.658538 -13.091922)
		(width 0.127)
		(layer "In11.Cu")
		(net "CLK_50M_RMII_BMC_OCP")
	)
	(segment
		(start 196.42455 -16.620744)
		(end 196.04355 -16.620744)
		(width 0.127)
		(layer "In11.Cu")
		(net "CLK_50M_RMII_BMC_OCP")
	)
	(segment
		(start 207.871568 -17.929352)
		(end 207.692244 -17.929352)
		(width 0.127)
		(layer "In11.Cu")
		(net "CLK_50M_RMII_BMC_OCP")
	)
	(segment
		(start 203.53655 -13.972794)
		(end 203.40955 -13.845794)
		(width 0.127)
		(layer "In11.Cu")
		(net "CLK_50M_RMII_BMC_OCP")
	)
	(segment
		(start 184.183274 -13.845794)
		(end 183.802274 -13.845794)
		(width 0.127)
		(layer "In11.Cu")
		(net "CLK_50M_RMII_BMC_OCP")
	)
	(segment
		(start 196.67855 -13.845794)
		(end 196.55155 -13.972794)
		(width 0.127)
		(layer "In11.Cu")
		(net "CLK_50M_RMII_BMC_OCP")
	)
	(segment
		(start 210.418426 -17.357852)
		(end 210.239102 -17.357852)
		(width 0.127)
		(layer "In11.Cu")
		(net "CLK_50M_RMII_BMC_OCP")
	)
	(segment
		(start 169.150538 -12.964922)
		(end 169.023538 -13.091922)
		(width 0.127)
		(layer "In11.Cu")
		(net "CLK_50M_RMII_BMC_OCP")
	)
	(segment
		(start 182.278274 -13.009118)
		(end 181.897274 -13.009118)
		(width 0.127)
		(layer "In11.Cu")
		(net "CLK_50M_RMII_BMC_OCP")
	)
	(segment
		(start 183.675274 -13.136118)
		(end 183.548274 -13.009118)
		(width 0.127)
		(layer "In11.Cu")
		(net "CLK_50M_RMII_BMC_OCP")
	)
	(segment
		(start 166.1668 -15.611348)
		(end 166.5478 -15.611348)
		(width 0.127)
		(layer "In11.Cu")
		(net "CLK_50M_RMII_BMC_OCP")
	)
	(segment
		(start 177.960274 -13.718794)
		(end 177.833274 -13.845794)
		(width 0.127)
		(layer "In11.Cu")
		(net "CLK_50M_RMII_BMC_OCP")
	)
	(segment
		(start 203.53655 -16.493744)
		(end 203.53655 -13.972794)
		(width 0.127)
		(layer "In11.Cu")
		(net "CLK_50M_RMII_BMC_OCP")
	)
	(segment
		(start 194.51955 -13.845794)
		(end 190.152274 -13.845794)
		(width 0.127)
		(layer "In11.Cu")
		(net "CLK_50M_RMII_BMC_OCP")
	)
	(segment
		(start 203.02855 -13.845794)
		(end 202.90155 -13.972794)
		(width 0.127)
		(layer "In11.Cu")
		(net "CLK_50M_RMII_BMC_OCP")
	)
	(segment
		(start 202.26655 -16.493744)
		(end 202.26655 -13.972794)
		(width 0.127)
		(layer "In11.Cu")
		(net "CLK_50M_RMII_BMC_OCP")
	)
	(segment
		(start 206.524352 -16.76146)
		(end 206.524352 -16.582136)
		(width 0.127)
		(layer "In11.Cu")
		(net "CLK_50M_RMII_BMC_OCP")
	)
	(segment
		(start 187.485274 -13.136118)
		(end 187.358274 -13.009118)
		(width 0.127)
		(layer "In11.Cu")
		(net "CLK_50M_RMII_BMC_OCP")
	)
	(segment
		(start 182.405274 -13.718794)
		(end 182.405274 -13.136118)
		(width 0.127)
		(layer "In11.Cu")
		(net "CLK_50M_RMII_BMC_OCP")
	)
	(segment
		(start 185.453274 -13.845794)
		(end 185.072274 -13.845794)
		(width 0.127)
		(layer "In11.Cu")
		(net "CLK_50M_RMII_BMC_OCP")
	)
	(segment
		(start 187.612274 -13.845794)
		(end 187.485274 -13.718794)
		(width 0.127)
		(layer "In11.Cu")
		(net "CLK_50M_RMII_BMC_OCP")
	)
	(segment
		(start 177.198274 -13.009118)
		(end 176.817274 -13.009118)
		(width 0.127)
		(layer "In11.Cu")
		(net "CLK_50M_RMII_BMC_OCP")
	)
	(segment
		(start 181.135274 -13.136118)
		(end 181.008274 -13.009118)
		(width 0.127)
		(layer "In11.Cu")
		(net "CLK_50M_RMII_BMC_OCP")
	)
	(segment
		(start 174.912274 -13.845794)
		(end 174.785274 -13.718794)
		(width 0.127)
		(layer "In11.Cu")
		(net "CLK_50M_RMII_BMC_OCP")
	)
	(segment
		(start 180.373274 -13.845794)
		(end 179.992274 -13.845794)
		(width 0.127)
		(layer "In11.Cu")
		(net "CLK_50M_RMII_BMC_OCP")
	)
	(segment
		(start 210.688174 -17.6276)
		(end 210.418426 -17.357852)
		(width 0.127)
		(layer "In11.Cu")
		(net "CLK_50M_RMII_BMC_OCP")
	)
	(segment
		(start 180.500274 -13.718794)
		(end 180.373274 -13.845794)
		(width 0.127)
		(layer "In11.Cu")
		(net "CLK_50M_RMII_BMC_OCP")
	)
	(segment
		(start 184.945274 -13.718794)
		(end 184.945274 -13.136118)
		(width 0.127)
		(layer "In11.Cu")
		(net "CLK_50M_RMII_BMC_OCP")
	)
	(segment
		(start 204.17155 -13.972794)
		(end 204.17155 -16.493744)
		(width 0.127)
		(layer "In11.Cu")
		(net "CLK_50M_RMII_BMC_OCP")
	)
	(segment
		(start 210.688174 -17.806924)
		(end 210.688174 -17.6276)
		(width 0.127)
		(layer "In11.Cu")
		(net "CLK_50M_RMII_BMC_OCP")
	)
	(segment
		(start 166.5478 -15.611348)
		(end 166.6748 -15.738348)
		(width 0.127)
		(layer "In11.Cu")
		(net "CLK_50M_RMII_BMC_OCP")
	)
	(segment
		(start 189.390274 -13.718794)
		(end 189.263274 -13.845794)
		(width 0.127)
		(layer "In11.Cu")
		(net "CLK_50M_RMII_BMC_OCP")
	)
	(segment
		(start 200.99655 -16.493744)
		(end 200.99655 -13.972794)
		(width 0.127)
		(layer "In11.Cu")
		(net "CLK_50M_RMII_BMC_OCP")
	)
	(segment
		(start 178.468274 -13.009118)
		(end 178.087274 -13.009118)
		(width 0.127)
		(layer "In11.Cu")
		(net "CLK_50M_RMII_BMC_OCP")
	)
	(segment
		(start 166.483538 -13.091922)
		(end 166.483538 -14.026134)
		(width 0.127)
		(layer "In11.Cu")
		(net "CLK_50M_RMII_BMC_OCP")
	)
	(segment
		(start 173.642274 -13.845794)
		(end 173.515274 -13.718794)
		(width 0.127)
		(layer "In11.Cu")
		(net "CLK_50M_RMII_BMC_OCP")
	)
	(segment
		(start 211.742782 -20.303744)
		(end 211.505292 -20.303744)
		(width 0.127)
		(layer "In11.Cu")
		(net "CLK_50M_RMII_BMC_OCP")
	)
	(segment
		(start 168.0718 -16.375888)
		(end 169.286682 -16.375888)
		(width 0.127)
		(layer "In11.Cu")
		(net "CLK_50M_RMII_BMC_OCP")
	)
	(segment
		(start 168.515538 -14.153134)
		(end 168.388538 -14.026134)
		(width 0.127)
		(layer "In11.Cu")
		(net "CLK_50M_RMII_BMC_OCP")
	)
	(segment
		(start 188.120274 -13.718794)
		(end 187.993274 -13.845794)
		(width 0.127)
		(layer "In11.Cu")
		(net "CLK_50M_RMII_BMC_OCP")
	)
	(segment
		(start 187.993274 -13.845794)
		(end 187.612274 -13.845794)
		(width 0.127)
		(layer "In11.Cu")
		(net "CLK_50M_RMII_BMC_OCP")
	)
	(segment
		(start 177.325274 -13.718794)
		(end 177.325274 -13.136118)
		(width 0.127)
		(layer "In11.Cu")
		(net "CLK_50M_RMII_BMC_OCP")
	)
	(segment
		(start 183.802274 -13.845794)
		(end 183.675274 -13.718794)
		(width 0.127)
		(layer "In11.Cu")
		(net "CLK_50M_RMII_BMC_OCP")
	)
	(segment
		(start 173.515274 -13.136118)
		(end 173.388274 -13.009118)
		(width 0.127)
		(layer "In11.Cu")
		(net "CLK_50M_RMII_BMC_OCP")
	)
	(segment
		(start 164.953188 -17.010888)
		(end 164.826188 -17.137888)
		(width 0.127)
		(layer "In11.Cu")
		(net "CLK_50M_RMII_BMC_OCP")
	)
	(segment
		(start 186.723274 -13.845794)
		(end 186.342274 -13.845794)
		(width 0.127)
		(layer "In11.Cu")
		(net "CLK_50M_RMII_BMC_OCP")
	)
	(segment
		(start 197.82155 -13.972794)
		(end 197.82155 -16.493744)
		(width 0.127)
		(layer "In11.Cu")
		(net "CLK_50M_RMII_BMC_OCP")
	)
	(segment
		(start 175.928274 -13.009118)
		(end 175.547274 -13.009118)
		(width 0.127)
		(layer "In11.Cu")
		(net "CLK_50M_RMII_BMC_OCP")
	)
	(segment
		(start 188.755274 -13.718794)
		(end 188.755274 -13.136118)
		(width 0.127)
		(layer "In11.Cu")
		(net "CLK_50M_RMII_BMC_OCP")
	)
	(segment
		(start 179.865274 -13.136118)
		(end 179.738274 -13.009118)
		(width 0.127)
		(layer "In11.Cu")
		(net "CLK_50M_RMII_BMC_OCP")
	)
	(segment
		(start 167.1828 -16.375888)
		(end 167.3098 -16.248888)
		(width 0.127)
		(layer "In11.Cu")
		(net "CLK_50M_RMII_BMC_OCP")
	)
	(segment
		(start 208.32064 -18.378424)
		(end 209.79003 -16.90878)
		(width 0.127)
		(layer "In11.Cu")
		(net "CLK_50M_RMII_BMC_OCP")
	)
	(segment
		(start 202.90155 -16.493744)
		(end 202.77455 -16.620744)
		(width 0.127)
		(layer "In11.Cu")
		(net "CLK_50M_RMII_BMC_OCP")
	)
	(segment
		(start 204.80655 -16.493744)
		(end 204.80655 -13.972794)
		(width 0.127)
		(layer "In11.Cu")
		(net "CLK_50M_RMII_BMC_OCP")
	)
	(segment
		(start 179.230274 -13.136118)
		(end 179.230274 -13.718794)
		(width 0.127)
		(layer "In11.Cu")
		(net "CLK_50M_RMII_BMC_OCP")
	)
	(segment
		(start 184.310274 -13.718794)
		(end 184.183274 -13.845794)
		(width 0.127)
		(layer "In11.Cu")
		(net "CLK_50M_RMII_BMC_OCP")
	)
	(segment
		(start 176.055274 -13.718794)
		(end 176.055274 -13.136118)
		(width 0.127)
		(layer "In11.Cu")
		(net "CLK_50M_RMII_BMC_OCP")
	)
	(segment
		(start 166.483538 -14.026134)
		(end 166.356538 -14.153134)
		(width 0.127)
		(layer "In11.Cu")
		(net "CLK_50M_RMII_BMC_OCP")
	)
	(segment
		(start 211.869782 -22.232366)
		(end 211.742782 -22.105366)
		(width 0.127)
		(layer "In11.Cu")
		(net "CLK_50M_RMII_BMC_OCP")
	)
	(segment
		(start 182.532274 -13.845794)
		(end 182.405274 -13.718794)
		(width 0.127)
		(layer "In11.Cu")
		(net "CLK_50M_RMII_BMC_OCP")
	)
	(segment
		(start 210.47456 -21.610066)
		(end 210.61426 -21.470366)
		(width 0.127)
		(layer "In11.Cu")
		(net "CLK_50M_RMII_BMC_OCP")
	)
	(segment
		(start 187.485274 -13.718794)
		(end 187.485274 -13.136118)
		(width 0.127)
		(layer "In11.Cu")
		(net "CLK_50M_RMII_BMC_OCP")
	)
	(segment
		(start 185.580274 -13.136118)
		(end 185.580274 -13.718794)
		(width 0.127)
		(layer "In11.Cu")
		(net "CLK_50M_RMII_BMC_OCP")
	)
	(segment
		(start 195.28155 -16.493744)
		(end 195.15455 -16.620744)
		(width 0.127)
		(layer "In11.Cu")
		(net "CLK_50M_RMII_BMC_OCP")
	)
	(segment
		(start 210.61426 -21.470366)
		(end 211.742782 -21.470366)
		(width 0.127)
		(layer "In11.Cu")
		(net "CLK_50M_RMII_BMC_OCP")
	)
	(segment
		(start 185.580274 -13.718794)
		(end 185.453274 -13.845794)
		(width 0.127)
		(layer "In11.Cu")
		(net "CLK_50M_RMII_BMC_OCP")
	)
	(segment
		(start 185.072274 -13.845794)
		(end 184.945274 -13.718794)
		(width 0.127)
		(layer "In11.Cu")
		(net "CLK_50M_RMII_BMC_OCP")
	)
	(segment
		(start 182.405274 -13.136118)
		(end 182.278274 -13.009118)
		(width 0.127)
		(layer "In11.Cu")
		(net "CLK_50M_RMII_BMC_OCP")
	)
	(segment
		(start 165.569646 -20.754848)
		(end 167.144446 -20.754848)
		(width 0.127)
		(layer "In11.Cu")
		(net "CLK_50M_RMII_BMC_OCP")
	)
	(segment
		(start 202.26655 -13.972794)
		(end 202.13955 -13.845794)
		(width 0.127)
		(layer "In11.Cu")
		(net "CLK_50M_RMII_BMC_OCP")
	)
	(segment
		(start 167.4368 -15.611348)
		(end 167.8178 -15.611348)
		(width 0.127)
		(layer "In11.Cu")
		(net "CLK_50M_RMII_BMC_OCP")
	)
	(segment
		(start 204.29855 -13.845794)
		(end 204.17155 -13.972794)
		(width 0.127)
		(layer "In11.Cu")
		(net "CLK_50M_RMII_BMC_OCP")
	)
	(segment
		(start 186.850274 -13.718794)
		(end 186.723274 -13.845794)
		(width 0.127)
		(layer "In11.Cu")
		(net "CLK_50M_RMII_BMC_OCP")
	)
	(segment
		(start 169.413682 -16.883888)
		(end 169.286682 -17.010888)
		(width 0.127)
		(layer "In11.Cu")
		(net "CLK_50M_RMII_BMC_OCP")
	)
	(segment
		(start 200.23455 -16.620744)
		(end 199.85355 -16.620744)
		(width 0.127)
		(layer "In11.Cu")
		(net "CLK_50M_RMII_BMC_OCP")
	)
	(segment
		(start 201.63155 -13.972794)
		(end 201.63155 -16.493744)
		(width 0.127)
		(layer "In11.Cu")
		(net "CLK_50M_RMII_BMC_OCP")
	)
	(segment
		(start 166.610538 -12.964922)
		(end 166.483538 -13.091922)
		(width 0.127)
		(layer "In11.Cu")
		(net "CLK_50M_RMII_BMC_OCP")
	)
	(segment
		(start 166.991538 -12.964922)
		(end 166.610538 -12.964922)
		(width 0.127)
		(layer "In11.Cu")
		(net "CLK_50M_RMII_BMC_OCP")
	)
	(segment
		(start 205.56855 -13.845794)
		(end 205.44155 -13.972794)
		(width 0.127)
		(layer "In11.Cu")
		(net "CLK_50M_RMII_BMC_OCP")
	)
	(segment
		(start 205.44155 -16.493744)
		(end 205.31455 -16.620744)
		(width 0.127)
		(layer "In11.Cu")
		(net "CLK_50M_RMII_BMC_OCP")
	)
	(segment
		(start 171.631864 -13.845794)
		(end 171.324524 -14.153134)
		(width 0.127)
		(layer "In11.Cu")
		(net "CLK_50M_RMII_BMC_OCP")
	)
	(segment
		(start 211.378292 -19.795744)
		(end 211.505292 -19.668744)
		(width 0.127)
		(layer "In11.Cu")
		(net "CLK_50M_RMII_BMC_OCP")
	)
	(segment
		(start 211.869782 -20.430744)
		(end 211.742782 -20.303744)
		(width 0.127)
		(layer "In11.Cu")
		(net "CLK_50M_RMII_BMC_OCP")
	)
	(segment
		(start 169.023538 -14.026134)
		(end 168.896538 -14.153134)
		(width 0.127)
		(layer "In11.Cu")
		(net "CLK_50M_RMII_BMC_OCP")
	)
	(segment
		(start 188.628274 -13.009118)
		(end 188.247274 -13.009118)
		(width 0.127)
		(layer "In11.Cu")
		(net "CLK_50M_RMII_BMC_OCP")
	)
	(segment
		(start 205.31455 -16.620744)
		(end 204.93355 -16.620744)
		(width 0.127)
		(layer "In11.Cu")
		(net "CLK_50M_RMII_BMC_OCP")
	)
	(segment
		(start 199.21855 -13.845794)
		(end 199.09155 -13.972794)
		(width 0.127)
		(layer "In11.Cu")
		(net "CLK_50M_RMII_BMC_OCP")
	)
	(segment
		(start 199.59955 -13.845794)
		(end 199.21855 -13.845794)
		(width 0.127)
		(layer "In11.Cu")
		(net "CLK_50M_RMII_BMC_OCP")
	)
	(segment
		(start 196.04355 -16.620744)
		(end 195.91655 -16.493744)
		(width 0.127)
		(layer "In11.Cu")
		(net "CLK_50M_RMII_BMC_OCP")
	)
	(segment
		(start 195.91655 -16.493744)
		(end 195.91655 -13.972794)
		(width 0.127)
		(layer "In11.Cu")
		(net "CLK_50M_RMII_BMC_OCP")
	)
	(segment
		(start 186.088274 -13.009118)
		(end 185.707274 -13.009118)
		(width 0.127)
		(layer "In11.Cu")
		(net "CLK_50M_RMII_BMC_OCP")
	)
	(segment
		(start 189.263274 -13.845794)
		(end 188.882274 -13.845794)
		(width 0.127)
		(layer "In11.Cu")
		(net "CLK_50M_RMII_BMC_OCP")
	)
	(segment
		(start 174.150274 -13.718794)
		(end 174.023274 -13.845794)
		(width 0.127)
		(layer "In11.Cu")
		(net "CLK_50M_RMII_BMC_OCP")
	)
	(segment
		(start 181.643274 -13.845794)
		(end 181.262274 -13.845794)
		(width 0.127)
		(layer "In11.Cu")
		(net "CLK_50M_RMII_BMC_OCP")
	)
	(segment
		(start 181.135274 -13.718794)
		(end 181.135274 -13.136118)
		(width 0.127)
		(layer "In11.Cu")
		(net "CLK_50M_RMII_BMC_OCP")
	)
	(segment
		(start 195.91655 -13.972794)
		(end 195.78955 -13.845794)
		(width 0.127)
		(layer "In11.Cu")
		(net "CLK_50M_RMII_BMC_OCP")
	)
	(segment
		(start 172.753274 -13.845794)
		(end 171.631864 -13.845794)
		(width 0.127)
		(layer "In11.Cu")
		(net "CLK_50M_RMII_BMC_OCP")
	)
	(segment
		(start 206.7941 -17.031208)
		(end 206.524352 -16.76146)
		(width 0.127)
		(layer "In11.Cu")
		(net "CLK_50M_RMII_BMC_OCP")
	)
	(segment
		(start 164.826188 -17.137888)
		(end 164.826188 -20.01139)
		(width 0.127)
		(layer "In11.Cu")
		(net "CLK_50M_RMII_BMC_OCP")
	)
	(segment
		(start 201.75855 -13.845794)
		(end 201.63155 -13.972794)
		(width 0.127)
		(layer "In11.Cu")
		(net "CLK_50M_RMII_BMC_OCP")
	)
	(segment
		(start 164.826188 -16.248888)
		(end 164.953188 -16.375888)
		(width 0.127)
		(layer "In11.Cu")
		(net "CLK_50M_RMII_BMC_OCP")
	)
	(segment
		(start 200.48855 -13.845794)
		(end 200.36155 -13.972794)
		(width 0.127)
		(layer "In11.Cu")
		(net "CLK_50M_RMII_BMC_OCP")
	)
	(segment
		(start 188.247274 -13.009118)
		(end 188.120274 -13.136118)
		(width 0.127)
		(layer "In11.Cu")
		(net "CLK_50M_RMII_BMC_OCP")
	)
	(segment
		(start 174.277274 -13.009118)
		(end 174.150274 -13.136118)
		(width 0.127)
		(layer "In11.Cu")
		(net "CLK_50M_RMII_BMC_OCP")
	)
	(segment
		(start 198.58355 -16.620744)
		(end 198.45655 -16.493744)
		(width 0.127)
		(layer "In11.Cu")
		(net "CLK_50M_RMII_BMC_OCP")
	)
	(segment
		(start 208.891886 -16.010636)
		(end 208.891886 -15.831312)
		(width 0.127)
		(layer "In11.Cu")
		(net "CLK_50M_RMII_BMC_OCP")
	)
	(segment
		(start 165.050978 -14.153134)
		(end 164.826188 -14.377924)
		(width 0.127)
		(layer "In11.Cu")
		(net "CLK_50M_RMII_BMC_OCP")
	)
	(segment
		(start 171.324524 -14.153134)
		(end 169.785538 -14.153134)
		(width 0.127)
		(layer "In11.Cu")
		(net "CLK_50M_RMII_BMC_OCP")
	)
	(segment
		(start 166.0398 -16.248888)
		(end 166.0398 -15.738348)
		(width 0.127)
		(layer "In11.Cu")
		(net "CLK_50M_RMII_BMC_OCP")
	)
	(segment
		(start 195.15455 -16.620744)
		(end 194.77355 -16.620744)
		(width 0.127)
		(layer "In11.Cu")
		(net "CLK_50M_RMII_BMC_OCP")
	)
	(segment
		(start 211.742782 -19.668744)
		(end 211.869782 -19.541744)
		(width 0.127)
		(layer "In11.Cu")
		(net "CLK_50M_RMII_BMC_OCP")
	)
	(segment
		(start 166.0398 -15.738348)
		(end 166.1668 -15.611348)
		(width 0.127)
		(layer "In11.Cu")
		(net "CLK_50M_RMII_BMC_OCP")
	)
	(segment
		(start 176.817274 -13.009118)
		(end 176.690274 -13.136118)
		(width 0.127)
		(layer "In11.Cu")
		(net "CLK_50M_RMII_BMC_OCP")
	)
	(segment
		(start 189.898274 -13.009118)
		(end 189.517274 -13.009118)
		(width 0.127)
		(layer "In11.Cu")
		(net "CLK_50M_RMII_BMC_OCP")
	)
	(segment
		(start 176.055274 -13.136118)
		(end 175.928274 -13.009118)
		(width 0.127)
		(layer "In11.Cu")
		(net "CLK_50M_RMII_BMC_OCP")
	)
	(segment
		(start 197.82155 -16.493744)
		(end 197.69455 -16.620744)
		(width 0.127)
		(layer "In11.Cu")
		(net "CLK_50M_RMII_BMC_OCP")
	)
	(segment
		(start 212.6615 -23.678134)
		(end 211.869782 -22.886416)
		(width 0.127)
		(layer "In11.Cu")
		(net "CLK_50M_RMII_BMC_OCP")
	)
	(segment
		(start 168.261538 -12.964922)
		(end 167.880538 -12.964922)
		(width 0.127)
		(layer "In11.Cu")
		(net "CLK_50M_RMII_BMC_OCP")
	)
	(segment
		(start 174.150274 -13.136118)
		(end 174.150274 -13.718794)
		(width 0.127)
		(layer "In11.Cu")
		(net "CLK_50M_RMII_BMC_OCP")
	)
	(segment
		(start 201.63155 -16.493744)
		(end 201.50455 -16.620744)
		(width 0.127)
		(layer "In11.Cu")
		(net "CLK_50M_RMII_BMC_OCP")
	)
	(segment
		(start 194.64655 -16.493744)
		(end 194.64655 -13.972794)
		(width 0.127)
		(layer "In11.Cu")
		(net "CLK_50M_RMII_BMC_OCP")
	)
	(segment
		(start 169.785538 -14.153134)
		(end 169.658538 -14.026134)
		(width 0.127)
		(layer "In11.Cu")
		(net "CLK_50M_RMII_BMC_OCP")
	)
	(segment
		(start 183.548274 -13.009118)
		(end 183.167274 -13.009118)
		(width 0.127)
		(layer "In11.Cu")
		(net "CLK_50M_RMII_BMC_OCP")
	)
	(segment
		(start 164.826188 -14.377924)
		(end 164.826188 -16.248888)
		(width 0.127)
		(layer "In11.Cu")
		(net "CLK_50M_RMII_BMC_OCP")
	)
	(segment
		(start 167.144446 -20.754848)
		(end 168.0464 -19.852894)
		(width 0.127)
		(layer "In11.Cu")
		(net "CLK_50M_RMII_BMC_OCP")
	)
	(segment
		(start 179.357274 -13.009118)
		(end 179.230274 -13.136118)
		(width 0.127)
		(layer "In11.Cu")
		(net "CLK_50M_RMII_BMC_OCP")
	)
	(segment
		(start 209.340958 -16.459708)
		(end 207.871568 -17.929352)
		(width 0.127)
		(layer "In11.Cu")
		(net "CLK_50M_RMII_BMC_OCP")
	)
	(segment
		(start 210.58886 -22.105366)
		(end 210.47456 -21.991066)
		(width 0.127)
		(layer "In11.Cu")
		(net "CLK_50M_RMII_BMC_OCP")
	)
	(segment
		(start 194.64655 -13.972794)
		(end 194.51955 -13.845794)
		(width 0.127)
		(layer "In11.Cu")
		(net "CLK_50M_RMII_BMC_OCP")
	)
	(segment
		(start 204.67955 -13.845794)
		(end 204.29855 -13.845794)
		(width 0.127)
		(layer "In11.Cu")
		(net "CLK_50M_RMII_BMC_OCP")
	)
	(segment
		(start 181.770274 -13.718794)
		(end 181.643274 -13.845794)
		(width 0.127)
		(layer "In11.Cu")
		(net "CLK_50M_RMII_BMC_OCP")
	)
	(segment
		(start 207.692244 -17.929352)
		(end 207.422496 -17.659604)
		(width 0.127)
		(layer "In11.Cu")
		(net "CLK_50M_RMII_BMC_OCP")
	)
	(segment
		(start 165.9128 -16.375888)
		(end 166.0398 -16.248888)
		(width 0.127)
		(layer "In11.Cu")
		(net "CLK_50M_RMII_BMC_OCP")
	)
	(segment
		(start 174.658274 -13.009118)
		(end 174.277274 -13.009118)
		(width 0.127)
		(layer "In11.Cu")
		(net "CLK_50M_RMII_BMC_OCP")
	)
	(segment
		(start 203.66355 -16.620744)
		(end 203.53655 -16.493744)
		(width 0.127)
		(layer "In11.Cu")
		(net "CLK_50M_RMII_BMC_OCP")
	)
	(segment
		(start 194.77355 -16.620744)
		(end 194.64655 -16.493744)
		(width 0.127)
		(layer "In11.Cu")
		(net "CLK_50M_RMII_BMC_OCP")
	)
	(segment
		(start 169.023538 -13.091922)
		(end 169.023538 -14.026134)
		(width 0.127)
		(layer "In11.Cu")
		(net "CLK_50M_RMII_BMC_OCP")
	)
	(segment
		(start 183.040274 -13.718794)
		(end 182.913274 -13.845794)
		(width 0.127)
		(layer "In11.Cu")
		(net "CLK_50M_RMII_BMC_OCP")
	)
	(segment
		(start 202.39355 -16.620744)
		(end 202.26655 -16.493744)
		(width 0.127)
		(layer "In11.Cu")
		(net "CLK_50M_RMII_BMC_OCP")
	)
	(segment
		(start 181.262274 -13.845794)
		(end 181.135274 -13.718794)
		(width 0.127)
		(layer "In11.Cu")
		(net "CLK_50M_RMII_BMC_OCP")
	)
	(segment
		(start 176.690274 -13.136118)
		(end 176.690274 -13.718794)
		(width 0.127)
		(layer "In11.Cu")
		(net "CLK_50M_RMII_BMC_OCP")
	)
	(segment
		(start 214.82431 -24.501094)
		(end 215.257888 -24.067516)
		(width 0.12954)
		(layer "F.Cu")
		(net "CLK_50M_RMII")
	)
	(segment
		(start 215.62441 -26.911554)
		(end 214.82431 -26.111454)
		(width 0.12954)
		(layer "F.Cu")
		(net "CLK_50M_RMII")
	)
	(segment
		(start 215.6206 -23.704804)
		(end 215.90381 -23.704804)
		(width 0.12954)
		(layer "F.Cu")
		(net "CLK_50M_RMII")
	)
	(segment
		(start 214.82431 -26.111454)
		(end 214.82431 -24.501094)
		(width 0.12954)
		(layer "F.Cu")
		(net "CLK_50M_RMII")
	)
	(segment
		(start 215.257888 -24.067516)
		(end 215.6206 -23.704804)
		(width 0.12954)
		(layer "F.Cu")
		(net "CLK_50M_RMII")
	)
	(segment
		(start 215.922352 -26.911554)
		(end 215.62441 -26.911554)
		(width 0.12954)
		(layer "F.Cu")
		(net "CLK_50M_RMII")
	)
	(via
		(at 215.257888 -24.067516)
		(size 0.508)
		(drill 0.254)
		(layers "F.Cu" "B.Cu")
		(net "CLK_50M_RMII")
	)
	(segment
		(start 211.210906 -15.943072)
		(end 212.541866 -17.274032)
		(width 0.12954)
		(layer "F.Cu")
		(net "CLK_50M_NCSI_OCP_SFF")
	)
	(segment
		(start 371.47754 -14.399768)
		(end 370.98986 -13.912088)
		(width 0.12954)
		(layer "F.Cu")
		(net "CLK_50M_NCSI_OCP_SFF")
	)
	(segment
		(start 370.845842 -15.321788)
		(end 371.17782 -15.321788)
		(width 0.12954)
		(layer "F.Cu")
		(net "CLK_50M_NCSI_OCP_SFF")
	)
	(segment
		(start 371.17782 -15.321788)
		(end 371.47754 -15.022068)
		(width 0.12954)
		(layer "F.Cu")
		(net "CLK_50M_NCSI_OCP_SFF")
	)
	(segment
		(start 371.47754 -15.022068)
		(end 371.47754 -14.399768)
		(width 0.12954)
		(layer "F.Cu")
		(net "CLK_50M_NCSI_OCP_SFF")
	)
	(segment
		(start 365.52886 -13.912088)
		(end 364.3884 -15.052548)
		(width 0.12954)
		(layer "F.Cu")
		(net "CLK_50M_NCSI_OCP_SFF")
	)
	(segment
		(start 370.98986 -13.912088)
		(end 365.52886 -13.912088)
		(width 0.12954)
		(layer "F.Cu")
		(net "CLK_50M_NCSI_OCP_SFF")
	)
	(via
		(at 364.3884 -15.052548)
		(size 0.508)
		(drill 0.254)
		(layers "F.Cu" "B.Cu")
		(net "CLK_50M_NCSI_OCP_SFF")
	)
	(via
		(at 212.541866 -17.274032)
		(size 0.508)
		(drill 0.254)
		(layers "F.Cu" "B.Cu")
		(net "CLK_50M_NCSI_OCP_SFF")
	)
	(segment
		(start 262.902954 -33.363408)
		(end 258.958334 -37.308028)
		(width 0.127)
		(layer "In11.Cu")
		(net "CLK_50M_NCSI_OCP_SFF")
	)
	(segment
		(start 278.569166 -21.300948)
		(end 266.506706 -33.363408)
		(width 0.127)
		(layer "In11.Cu")
		(net "CLK_50M_NCSI_OCP_SFF")
	)
	(segment
		(start 245.256558 -38.410388)
		(end 241.195098 -42.471848)
		(width 0.127)
		(layer "In11.Cu")
		(net "CLK_50M_NCSI_OCP_SFF")
	)
	(segment
		(start 312.163714 -13.869416)
		(end 311.593484 -13.299186)
		(width 0.127)
		(layer "In11.Cu")
		(net "CLK_50M_NCSI_OCP_SFF")
	)
	(segment
		(start 293.509954 -21.300948)
		(end 278.569166 -21.300948)
		(width 0.127)
		(layer "In11.Cu")
		(net "CLK_50M_NCSI_OCP_SFF")
	)
	(segment
		(start 247.917716 -37.308028)
		(end 245.256558 -38.410388)
		(width 0.127)
		(layer "In11.Cu")
		(net "CLK_50M_NCSI_OCP_SFF")
	)
	(segment
		(start 320.661284 -13.869416)
		(end 312.163714 -13.869416)
		(width 0.127)
		(layer "In11.Cu")
		(net "CLK_50M_NCSI_OCP_SFF")
	)
	(segment
		(start 217.795602 -22.527768)
		(end 212.541866 -17.274032)
		(width 0.127)
		(layer "In11.Cu")
		(net "CLK_50M_NCSI_OCP_SFF")
	)
	(segment
		(start 258.958334 -37.308028)
		(end 247.917716 -37.308028)
		(width 0.127)
		(layer "In11.Cu")
		(net "CLK_50M_NCSI_OCP_SFF")
	)
	(segment
		(start 218.268804 -37.436298)
		(end 216.29624 -35.463734)
		(width 0.127)
		(layer "In11.Cu")
		(net "CLK_50M_NCSI_OCP_SFF")
	)
	(segment
		(start 266.506706 -33.363408)
		(end 262.902954 -33.363408)
		(width 0.127)
		(layer "In11.Cu")
		(net "CLK_50M_NCSI_OCP_SFF")
	)
	(segment
		(start 301.511716 -13.299186)
		(end 293.509954 -21.300948)
		(width 0.127)
		(layer "In11.Cu")
		(net "CLK_50M_NCSI_OCP_SFF")
	)
	(segment
		(start 217.795602 -30.761432)
		(end 217.795602 -22.527768)
		(width 0.127)
		(layer "In11.Cu")
		(net "CLK_50M_NCSI_OCP_SFF")
	)
	(segment
		(start 221.50578 -37.679122)
		(end 221.262956 -37.436298)
		(width 0.127)
		(layer "In11.Cu")
		(net "CLK_50M_NCSI_OCP_SFF")
	)
	(segment
		(start 221.262956 -37.436298)
		(end 218.268804 -37.436298)
		(width 0.127)
		(layer "In11.Cu")
		(net "CLK_50M_NCSI_OCP_SFF")
	)
	(segment
		(start 216.29624 -32.260794)
		(end 217.795602 -30.761432)
		(width 0.127)
		(layer "In11.Cu")
		(net "CLK_50M_NCSI_OCP_SFF")
	)
	(segment
		(start 216.29624 -35.463734)
		(end 216.29624 -32.260794)
		(width 0.127)
		(layer "In11.Cu")
		(net "CLK_50M_NCSI_OCP_SFF")
	)
	(segment
		(start 224.90176 -39.419022)
		(end 223.16186 -37.679122)
		(width 0.127)
		(layer "In11.Cu")
		(net "CLK_50M_NCSI_OCP_SFF")
	)
	(segment
		(start 364.3884 -15.052548)
		(end 364.077504 -15.052548)
		(width 0.127)
		(layer "In11.Cu")
		(net "CLK_50M_NCSI_OCP_SFF")
	)
	(segment
		(start 233.949494 -42.471848)
		(end 230.896668 -39.419022)
		(width 0.127)
		(layer "In11.Cu")
		(net "CLK_50M_NCSI_OCP_SFF")
	)
	(segment
		(start 241.195098 -42.471848)
		(end 233.949494 -42.471848)
		(width 0.127)
		(layer "In11.Cu")
		(net "CLK_50M_NCSI_OCP_SFF")
	)
	(segment
		(start 321.299078 -13.231622)
		(end 320.661284 -13.869416)
		(width 0.127)
		(layer "In11.Cu")
		(net "CLK_50M_NCSI_OCP_SFF")
	)
	(segment
		(start 223.16186 -37.679122)
		(end 221.50578 -37.679122)
		(width 0.127)
		(layer "In11.Cu")
		(net "CLK_50M_NCSI_OCP_SFF")
	)
	(segment
		(start 333.714344 -13.231622)
		(end 321.299078 -13.231622)
		(width 0.127)
		(layer "In11.Cu")
		(net "CLK_50M_NCSI_OCP_SFF")
	)
	(segment
		(start 230.896668 -39.419022)
		(end 224.90176 -39.419022)
		(width 0.127)
		(layer "In11.Cu")
		(net "CLK_50M_NCSI_OCP_SFF")
	)
	(segment
		(start 364.077504 -15.052548)
		(end 333.714344 -13.231622)
		(width 0.127)
		(layer "In11.Cu")
		(net "CLK_50M_NCSI_OCP_SFF")
	)
	(segment
		(start 311.593484 -13.299186)
		(end 301.511716 -13.299186)
		(width 0.127)
		(layer "In11.Cu")
		(net "CLK_50M_NCSI_OCP_SFF")
	)
	(segment
		(start 213.369398 -17.40916)
		(end 213.369398 -14.845792)
		(width 0.12954)
		(layer "F.Cu")
		(net "CLK_50M_NCSI_OCP_1")
	)
	(segment
		(start 211.313268 -18.045684)
		(end 212.732874 -18.045684)
		(width 0.12954)
		(layer "F.Cu")
		(net "CLK_50M_NCSI_OCP_1")
	)
	(segment
		(start 211.210906 -16.743172)
		(end 211.210906 -17.943322)
		(width 0.12954)
		(layer "F.Cu")
		(net "CLK_50M_NCSI_OCP_1")
	)
	(segment
		(start 211.210906 -17.943322)
		(end 211.313268 -18.045684)
		(width 0.12954)
		(layer "F.Cu")
		(net "CLK_50M_NCSI_OCP_1")
	)
	(segment
		(start 212.732874 -18.045684)
		(end 213.369398 -17.40916)
		(width 0.12954)
		(layer "F.Cu")
		(net "CLK_50M_NCSI_OCP_1")
	)
	(via
		(at 211.210906 -17.943322)
		(size 0.762)
		(drill 0.381)
		(layers "F.Cu" "B.Cu")
		(net "CLK_50M_NCSI_OCP_1")
	)
	(segment
		(start 214.669624 -21.661628)
		(end 214.669624 -20.687792)
		(width 0.12954)
		(layer "F.Cu")
		(net "CLK_50M_EN")
	)
	(segment
		(start 213.979506 -23.704804)
		(end 213.762336 -23.921974)
		(width 0.12954)
		(layer "F.Cu")
		(net "CLK_50M_EN")
	)
	(segment
		(start 213.802468 -25.201626)
		(end 213.802468 -25.311354)
		(width 0.12954)
		(layer "F.Cu")
		(net "CLK_50M_EN")
	)
	(segment
		(start 213.762336 -25.161494)
		(end 213.802468 -25.201626)
		(width 0.12954)
		(layer "F.Cu")
		(net "CLK_50M_EN")
	)
	(segment
		(start 213.762336 -23.921974)
		(end 213.762336 -25.161494)
		(width 0.12954)
		(layer "F.Cu")
		(net "CLK_50M_EN")
	)
	(segment
		(start 214.61349 -23.704804)
		(end 215.11133 -23.206964)
		(width 0.12954)
		(layer "F.Cu")
		(net "CLK_50M_EN")
	)
	(segment
		(start 214.61349 -23.704804)
		(end 213.979506 -23.704804)
		(width 0.12954)
		(layer "F.Cu")
		(net "CLK_50M_EN")
	)
	(segment
		(start 215.11133 -23.206964)
		(end 215.11133 -22.103334)
		(width 0.12954)
		(layer "F.Cu")
		(net "CLK_50M_EN")
	)
	(segment
		(start 215.11133 -22.103334)
		(end 214.669624 -21.661628)
		(width 0.12954)
		(layer "F.Cu")
		(net "CLK_50M_EN")
	)
	(via
		(at 213.762336 -23.921974)
		(size 0.508)
		(drill 0.254)
		(layers "F.Cu" "B.Cu")
		(net "CLK_50M_EN")
	)
	(segment
		(start 214.00135 -21.493734)
		(end 213.334092 -22.160992)
		(width 0.12954)
		(layer "F.Cu")
		(net "CLK_50M_BMC_MAC_R")
	)
	(segment
		(start 213.334092 -22.160992)
		(end 213.334092 -22.847046)
		(width 0.12954)
		(layer "F.Cu")
		(net "CLK_50M_BMC_MAC_R")
	)
	(segment
		(start 214.00135 -20.705826)
		(end 214.00135 -21.493734)
		(width 0.12954)
		(layer "F.Cu")
		(net "CLK_50M_BMC_MAC_R")
	)
	(segment
		(start 214.019384 -20.687792)
		(end 214.00135 -20.705826)
		(width 0.12954)
		(layer "F.Cu")
		(net "CLK_50M_BMC_MAC_R")
	)
	(segment
		(start 213.334092 -22.847046)
		(end 213.4616 -22.974554)
		(width 0.12954)
		(layer "F.Cu")
		(net "CLK_50M_BMC_MAC_R")
	)
	(via
		(at 213.334092 -22.160992)
		(size 0.508)
		(drill 0.254)
		(layers "F.Cu" "B.Cu")
		(net "CLK_50M_BMC_MAC_R")
	)
	(segment
		(start 338.331556 -68.948808)
		(end 338.331556 -69.398388)
		(width 0.13208)
		(layer "F.Cu")
		(net "CLK_25M_PCH_REF_NS_DP")
	)
	(segment
		(start 338.716366 -62.032388)
		(end 338.716366 -62.286388)
		(width 0.0889)
		(layer "F.Cu")
		(net "CLK_25M_PCH_REF_NS_DP")
	)
	(segment
		(start 338.456016 -67.323208)
		(end 338.456016 -67.704208)
		(width 0.13208)
		(layer "F.Cu")
		(net "CLK_25M_PCH_REF_NS_DP")
	)
	(segment
		(start 250.812554 -109.523022)
		(end 250.80976 -109.523022)
		(width 0.13208)
		(layer "F.Cu")
		(net "CLK_25M_PCH_REF_NS_DP")
	)
	(segment
		(start 338.716366 -63.434468)
		(end 338.716366 -63.688468)
		(width 0.0889)
		(layer "F.Cu")
		(net "CLK_25M_PCH_REF_NS_DP")
	)
	(segment
		(start 338.716366 -64.135508)
		(end 338.716366 -64.389508)
		(width 0.0889)
		(layer "F.Cu")
		(net "CLK_25M_PCH_REF_NS_DP")
	)
	(segment
		(start 338.716366 -64.836548)
		(end 338.716366 -65.090548)
		(width 0.0889)
		(layer "F.Cu")
		(net "CLK_25M_PCH_REF_NS_DP")
	)
	(segment
		(start 338.331556 -67.828668)
		(end 338.331556 -68.308728)
		(width 0.13208)
		(layer "F.Cu")
		(net "CLK_25M_PCH_REF_NS_DP")
	)
	(segment
		(start 338.619846 -61.681868)
		(end 338.619846 -61.935868)
		(width 0.0889)
		(layer "F.Cu")
		(net "CLK_25M_PCH_REF_NS_DP")
	)
	(segment
		(start 338.456016 -69.903848)
		(end 338.331556 -70.028308)
		(width 0.13208)
		(layer "F.Cu")
		(net "CLK_25M_PCH_REF_NS_DP")
	)
	(segment
		(start 338.331556 -69.398388)
		(end 338.456016 -69.522848)
		(width 0.13208)
		(layer "F.Cu")
		(net "CLK_25M_PCH_REF_NS_DP")
	)
	(segment
		(start 338.619846 -64.486028)
		(end 338.619846 -64.740028)
		(width 0.0889)
		(layer "F.Cu")
		(net "CLK_25M_PCH_REF_NS_DP")
	)
	(segment
		(start 338.331556 -68.308728)
		(end 338.453476 -68.430648)
		(width 0.13208)
		(layer "F.Cu")
		(net "CLK_25M_PCH_REF_NS_DP")
	)
	(segment
		(start 338.716366 -63.688468)
		(end 338.619846 -63.784988)
		(width 0.0889)
		(layer "F.Cu")
		(net "CLK_25M_PCH_REF_NS_DP")
	)
	(segment
		(start 335.824576 -73.396094)
		(end 335.824576 -75.696318)
		(width 0.13208)
		(layer "F.Cu")
		(net "CLK_25M_PCH_REF_NS_DP")
	)
	(segment
		(start 338.716366 -62.733428)
		(end 338.716366 -62.987428)
		(width 0.0889)
		(layer "F.Cu")
		(net "CLK_25M_PCH_REF_NS_DP")
	)
	(segment
		(start 338.619846 -62.636908)
		(end 338.716366 -62.733428)
		(width 0.0889)
		(layer "F.Cu")
		(net "CLK_25M_PCH_REF_NS_DP")
	)
	(segment
		(start 338.619846 -64.038988)
		(end 338.716366 -64.135508)
		(width 0.0889)
		(layer "F.Cu")
		(net "CLK_25M_PCH_REF_NS_DP")
	)
	(segment
		(start 338.619846 -64.740028)
		(end 338.716366 -64.836548)
		(width 0.0889)
		(layer "F.Cu")
		(net "CLK_25M_PCH_REF_NS_DP")
	)
	(segment
		(start 338.32292 -59.890406)
		(end 338.619846 -60.187332)
		(width 0.0889)
		(layer "F.Cu")
		(net "CLK_25M_PCH_REF_NS_DP")
	)
	(segment
		(start 338.716366 -60.630308)
		(end 338.716366 -60.884308)
		(width 0.0889)
		(layer "F.Cu")
		(net "CLK_25M_PCH_REF_NS_DP")
	)
	(segment
		(start 338.716366 -64.389508)
		(end 338.619846 -64.486028)
		(width 0.0889)
		(layer "F.Cu")
		(net "CLK_25M_PCH_REF_NS_DP")
	)
	(segment
		(start 338.453476 -68.430648)
		(end 338.453476 -68.826888)
		(width 0.13208)
		(layer "F.Cu")
		(net "CLK_25M_PCH_REF_NS_DP")
	)
	(segment
		(start 338.40039 -58.850276)
		(end 338.40039 -59.450224)
		(width 0.0889)
		(layer "F.Cu")
		(net "CLK_25M_PCH_REF_NS_DP")
	)
	(segment
		(start 338.331556 -66.391028)
		(end 338.331556 -66.413126)
		(width 0.0889)
		(layer "F.Cu")
		(net "CLK_25M_PCH_REF_NS_DP")
	)
	(segment
		(start 338.619846 -61.234828)
		(end 338.716366 -61.331348)
		(width 0.0889)
		(layer "F.Cu")
		(net "CLK_25M_PCH_REF_NS_DP")
	)
	(segment
		(start 250.733306 -108.592874)
		(end 251.09932 -108.958888)
		(width 0.13208)
		(layer "F.Cu")
		(net "CLK_25M_PCH_REF_NS_DP")
	)
	(segment
		(start 338.619846 -61.935868)
		(end 338.716366 -62.032388)
		(width 0.0889)
		(layer "F.Cu")
		(net "CLK_25M_PCH_REF_NS_DP")
	)
	(segment
		(start 338.331556 -70.028308)
		(end 338.331556 -70.642734)
		(width 0.13208)
		(layer "F.Cu")
		(net "CLK_25M_PCH_REF_NS_DP")
	)
	(segment
		(start 338.40039 -59.450224)
		(end 338.32292 -59.527694)
		(width 0.0889)
		(layer "F.Cu")
		(net "CLK_25M_PCH_REF_NS_DP")
	)
	(segment
		(start 338.619846 -62.382908)
		(end 338.619846 -62.636908)
		(width 0.0889)
		(layer "F.Cu")
		(net "CLK_25M_PCH_REF_NS_DP")
	)
	(segment
		(start 338.716366 -61.331348)
		(end 338.716366 -61.585348)
		(width 0.0889)
		(layer "F.Cu")
		(net "CLK_25M_PCH_REF_NS_DP")
	)
	(segment
		(start 338.331556 -70.642734)
		(end 338.157566 -71.063104)
		(width 0.13208)
		(layer "F.Cu")
		(net "CLK_25M_PCH_REF_NS_DP")
	)
	(segment
		(start 338.297266 -66.356738)
		(end 338.331556 -66.391028)
		(width 0.0889)
		(layer "F.Cu")
		(net "CLK_25M_PCH_REF_NS_DP")
	)
	(segment
		(start 338.619846 -60.980828)
		(end 338.619846 -61.234828)
		(width 0.0889)
		(layer "F.Cu")
		(net "CLK_25M_PCH_REF_NS_DP")
	)
	(segment
		(start 338.619846 -63.784988)
		(end 338.619846 -64.038988)
		(width 0.0889)
		(layer "F.Cu")
		(net "CLK_25M_PCH_REF_NS_DP")
	)
	(segment
		(start 338.453476 -68.826888)
		(end 338.331556 -68.948808)
		(width 0.13208)
		(layer "F.Cu")
		(net "CLK_25M_PCH_REF_NS_DP")
	)
	(segment
		(start 338.456016 -67.704208)
		(end 338.331556 -67.828668)
		(width 0.13208)
		(layer "F.Cu")
		(net "CLK_25M_PCH_REF_NS_DP")
	)
	(segment
		(start 338.297266 -65.871344)
		(end 338.297266 -66.356738)
		(width 0.0889)
		(layer "F.Cu")
		(net "CLK_25M_PCH_REF_NS_DP")
	)
	(segment
		(start 338.619846 -65.187068)
		(end 338.619846 -65.548764)
		(width 0.0889)
		(layer "F.Cu")
		(net "CLK_25M_PCH_REF_NS_DP")
	)
	(segment
		(start 338.619846 -63.083948)
		(end 338.619846 -63.337948)
		(width 0.0889)
		(layer "F.Cu")
		(net "CLK_25M_PCH_REF_NS_DP")
	)
	(segment
		(start 338.331556 -66.413126)
		(end 338.331556 -67.198748)
		(width 0.13208)
		(layer "F.Cu")
		(net "CLK_25M_PCH_REF_NS_DP")
	)
	(segment
		(start 338.716366 -65.090548)
		(end 338.619846 -65.187068)
		(width 0.0889)
		(layer "F.Cu")
		(net "CLK_25M_PCH_REF_NS_DP")
	)
	(segment
		(start 338.157566 -71.063104)
		(end 335.824576 -73.396094)
		(width 0.13208)
		(layer "F.Cu")
		(net "CLK_25M_PCH_REF_NS_DP")
	)
	(segment
		(start 338.619846 -60.187332)
		(end 338.619846 -60.533788)
		(width 0.0889)
		(layer "F.Cu")
		(net "CLK_25M_PCH_REF_NS_DP")
	)
	(segment
		(start 338.619846 -60.533788)
		(end 338.716366 -60.630308)
		(width 0.0889)
		(layer "F.Cu")
		(net "CLK_25M_PCH_REF_NS_DP")
	)
	(segment
		(start 338.716366 -62.286388)
		(end 338.619846 -62.382908)
		(width 0.0889)
		(layer "F.Cu")
		(net "CLK_25M_PCH_REF_NS_DP")
	)
	(segment
		(start 338.716366 -61.585348)
		(end 338.619846 -61.681868)
		(width 0.0889)
		(layer "F.Cu")
		(net "CLK_25M_PCH_REF_NS_DP")
	)
	(segment
		(start 251.09932 -108.958888)
		(end 251.09932 -109.236256)
		(width 0.13208)
		(layer "F.Cu")
		(net "CLK_25M_PCH_REF_NS_DP")
	)
	(segment
		(start 338.619846 -65.548764)
		(end 338.297266 -65.871344)
		(width 0.0889)
		(layer "F.Cu")
		(net "CLK_25M_PCH_REF_NS_DP")
	)
	(segment
		(start 338.331556 -67.198748)
		(end 338.456016 -67.323208)
		(width 0.13208)
		(layer "F.Cu")
		(net "CLK_25M_PCH_REF_NS_DP")
	)
	(segment
		(start 338.716366 -62.987428)
		(end 338.619846 -63.083948)
		(width 0.0889)
		(layer "F.Cu")
		(net "CLK_25M_PCH_REF_NS_DP")
	)
	(segment
		(start 338.716366 -60.884308)
		(end 338.619846 -60.980828)
		(width 0.0889)
		(layer "F.Cu")
		(net "CLK_25M_PCH_REF_NS_DP")
	)
	(segment
		(start 338.619846 -63.337948)
		(end 338.716366 -63.434468)
		(width 0.0889)
		(layer "F.Cu")
		(net "CLK_25M_PCH_REF_NS_DP")
	)
	(segment
		(start 335.824576 -75.696318)
		(end 336.118962 -75.990704)
		(width 0.13208)
		(layer "F.Cu")
		(net "CLK_25M_PCH_REF_NS_DP")
	)
	(segment
		(start 338.456016 -69.522848)
		(end 338.456016 -69.903848)
		(width 0.13208)
		(layer "F.Cu")
		(net "CLK_25M_PCH_REF_NS_DP")
	)
	(segment
		(start 251.09932 -109.236256)
		(end 250.812554 -109.523022)
		(width 0.13208)
		(layer "F.Cu")
		(net "CLK_25M_PCH_REF_NS_DP")
	)
	(segment
		(start 338.32292 -59.527694)
		(end 338.32292 -59.890406)
		(width 0.0889)
		(layer "F.Cu")
		(net "CLK_25M_PCH_REF_NS_DP")
	)
	(via
		(at 336.118962 -75.990704)
		(size 0.508)
		(drill 0.254)
		(layers "F.Cu" "B.Cu")
		(net "CLK_25M_PCH_REF_NS_DP")
	)
	(via
		(at 250.80976 -109.523022)
		(size 0.508)
		(drill 0.254)
		(layers "F.Cu" "B.Cu")
		(net "CLK_25M_PCH_REF_NS_DP")
	)
	(segment
		(start 247.746266 -109.015022)
		(end 248.00687 -109.275626)
		(width 0.14732)
		(layer "In4.Cu")
		(net "CLK_25M_PCH_REF_NS_DP")
	)
	(segment
		(start 258.154932 -91.396058)
		(end 255.960626 -92.30487)
		(width 0.14732)
		(layer "In4.Cu")
		(net "CLK_25M_PCH_REF_NS_DP")
	)
	(segment
		(start 305.662584 -88.346026)
		(end 303.26457 -89.339166)
		(width 0.14732)
		(layer "In4.Cu")
		(net "CLK_25M_PCH_REF_NS_DP")
	)
	(segment
		(start 244.67312 -99.088194)
		(end 244.510306 -99.155504)
		(width 0.14732)
		(layer "In4.Cu")
		(net "CLK_25M_PCH_REF_NS_DP")
	)
	(segment
		(start 247.288304 -108.55706)
		(end 247.288304 -108.754672)
		(width 0.14732)
		(layer "In4.Cu")
		(net "CLK_25M_PCH_REF_NS_DP")
	)
	(segment
		(start 251.1044 -109.817662)
		(end 250.80976 -109.523022)
		(width 0.14732)
		(layer "In4.Cu")
		(net "CLK_25M_PCH_REF_NS_DP")
	)
	(segment
		(start 248.985786 -110.452154)
		(end 250.678442 -110.452154)
		(width 0.14732)
		(layer "In4.Cu")
		(net "CLK_25M_PCH_REF_NS_DP")
	)
	(segment
		(start 245.590568 -106.859324)
		(end 245.851172 -107.119928)
		(width 0.14732)
		(layer "In4.Cu")
		(net "CLK_25M_PCH_REF_NS_DP")
	)
	(segment
		(start 247.548654 -109.015022)
		(end 247.746266 -109.015022)
		(width 0.14732)
		(layer "In4.Cu")
		(net "CLK_25M_PCH_REF_NS_DP")
	)
	(segment
		(start 288.251138 -89.339166)
		(end 283.285184 -91.396058)
		(width 0.14732)
		(layer "In4.Cu")
		(net "CLK_25M_PCH_REF_NS_DP")
	)
	(segment
		(start 243.842032 -103.812848)
		(end 243.963952 -103.934768)
		(width 0.14732)
		(layer "In4.Cu")
		(net "CLK_25M_PCH_REF_NS_DP")
	)
	(segment
		(start 320.86677 -85.321648)
		(end 305.662584 -88.346026)
		(width 0.14732)
		(layer "In4.Cu")
		(net "CLK_25M_PCH_REF_NS_DP")
	)
	(segment
		(start 246.097044 -95.325184)
		(end 245.20271 -97.484438)
		(width 0.14732)
		(layer "In4.Cu")
		(net "CLK_25M_PCH_REF_NS_DP")
	)
	(segment
		(start 246.569738 -108.036106)
		(end 246.830088 -108.296456)
		(width 0.14732)
		(layer "In4.Cu")
		(net "CLK_25M_PCH_REF_NS_DP")
	)
	(segment
		(start 335.055464 -82.884264)
		(end 332.31582 -84.02701)
		(width 0.14732)
		(layer "In4.Cu")
		(net "CLK_25M_PCH_REF_NS_DP")
	)
	(segment
		(start 245.392956 -106.859324)
		(end 245.590568 -106.859324)
		(width 0.14732)
		(layer "In4.Cu")
		(net "CLK_25M_PCH_REF_NS_DP")
	)
	(segment
		(start 246.111522 -107.57789)
		(end 246.309134 -107.57789)
		(width 0.14732)
		(layer "In4.Cu")
		(net "CLK_25M_PCH_REF_NS_DP")
	)
	(segment
		(start 250.4059 -93.475048)
		(end 247.94718 -93.475048)
		(width 0.14732)
		(layer "In4.Cu")
		(net "CLK_25M_PCH_REF_NS_DP")
	)
	(segment
		(start 245.132606 -106.598974)
		(end 245.392956 -106.859324)
		(width 0.14732)
		(layer "In4.Cu")
		(net "CLK_25M_PCH_REF_NS_DP")
	)
	(segment
		(start 247.288304 -108.754672)
		(end 247.548654 -109.015022)
		(width 0.14732)
		(layer "In4.Cu")
		(net "CLK_25M_PCH_REF_NS_DP")
	)
	(segment
		(start 248.26722 -109.733588)
		(end 248.464832 -109.733588)
		(width 0.14732)
		(layer "In4.Cu")
		(net "CLK_25M_PCH_REF_NS_DP")
	)
	(segment
		(start 243.963952 -104.371648)
		(end 243.842032 -104.493568)
		(width 0.14732)
		(layer "In4.Cu")
		(net "CLK_25M_PCH_REF_NS_DP")
	)
	(segment
		(start 247.0277 -108.296456)
		(end 247.288304 -108.55706)
		(width 0.14732)
		(layer "In4.Cu")
		(net "CLK_25M_PCH_REF_NS_DP")
	)
	(segment
		(start 303.26457 -89.339166)
		(end 288.251138 -89.339166)
		(width 0.14732)
		(layer "In4.Cu")
		(net "CLK_25M_PCH_REF_NS_DP")
	)
	(segment
		(start 243.842032 -100.768912)
		(end 243.842032 -103.812848)
		(width 0.14732)
		(layer "In4.Cu")
		(net "CLK_25M_PCH_REF_NS_DP")
	)
	(segment
		(start 244.940074 -98.118168)
		(end 244.772942 -98.521774)
		(width 0.14732)
		(layer "In4.Cu")
		(net "CLK_25M_PCH_REF_NS_DP")
	)
	(segment
		(start 243.963952 -103.934768)
		(end 243.963952 -104.371648)
		(width 0.14732)
		(layer "In4.Cu")
		(net "CLK_25M_PCH_REF_NS_DP")
	)
	(segment
		(start 248.725436 -109.994192)
		(end 248.725436 -110.191804)
		(width 0.14732)
		(layer "In4.Cu")
		(net "CLK_25M_PCH_REF_NS_DP")
	)
	(segment
		(start 250.678442 -110.452154)
		(end 251.1044 -110.026196)
		(width 0.14732)
		(layer "In4.Cu")
		(net "CLK_25M_PCH_REF_NS_DP")
	)
	(segment
		(start 251.576078 -92.30487)
		(end 250.4059 -93.475048)
		(width 0.14732)
		(layer "In4.Cu")
		(net "CLK_25M_PCH_REF_NS_DP")
	)
	(segment
		(start 245.132606 -106.401362)
		(end 245.132606 -106.598974)
		(width 0.14732)
		(layer "In4.Cu")
		(net "CLK_25M_PCH_REF_NS_DP")
	)
	(segment
		(start 325.805292 -85.321648)
		(end 320.86677 -85.321648)
		(width 0.14732)
		(layer "In4.Cu")
		(net "CLK_25M_PCH_REF_NS_DP")
	)
	(segment
		(start 332.31582 -84.02701)
		(end 332.273148 -84.035392)
		(width 0.14732)
		(layer "In4.Cu")
		(net "CLK_25M_PCH_REF_NS_DP")
	)
	(segment
		(start 335.824322 -78.318614)
		(end 336.41538 -79.74584)
		(width 0.14732)
		(layer "In4.Cu")
		(net "CLK_25M_PCH_REF_NS_DP")
	)
	(segment
		(start 255.960626 -92.30487)
		(end 251.576078 -92.30487)
		(width 0.14732)
		(layer "In4.Cu")
		(net "CLK_25M_PCH_REF_NS_DP")
	)
	(segment
		(start 245.851172 -107.119928)
		(end 245.851172 -107.31754)
		(width 0.14732)
		(layer "In4.Cu")
		(net "CLK_25M_PCH_REF_NS_DP")
	)
	(segment
		(start 336.118962 -75.990704)
		(end 335.824322 -76.285344)
		(width 0.14732)
		(layer "In4.Cu")
		(net "CLK_25M_PCH_REF_NS_DP")
	)
	(segment
		(start 251.1044 -110.026196)
		(end 251.1044 -109.817662)
		(width 0.14732)
		(layer "In4.Cu")
		(net "CLK_25M_PCH_REF_NS_DP")
	)
	(segment
		(start 245.851172 -107.31754)
		(end 246.111522 -107.57789)
		(width 0.14732)
		(layer "In4.Cu")
		(net "CLK_25M_PCH_REF_NS_DP")
	)
	(segment
		(start 244.872002 -106.140758)
		(end 245.132606 -106.401362)
		(width 0.14732)
		(layer "In4.Cu")
		(net "CLK_25M_PCH_REF_NS_DP")
	)
	(segment
		(start 243.842032 -105.3084)
		(end 244.67439 -106.140758)
		(width 0.14732)
		(layer "In4.Cu")
		(net "CLK_25M_PCH_REF_NS_DP")
	)
	(segment
		(start 248.464832 -109.733588)
		(end 248.725436 -109.994192)
		(width 0.14732)
		(layer "In4.Cu")
		(net "CLK_25M_PCH_REF_NS_DP")
	)
	(segment
		(start 246.569738 -107.838494)
		(end 246.569738 -108.036106)
		(width 0.14732)
		(layer "In4.Cu")
		(net "CLK_25M_PCH_REF_NS_DP")
	)
	(segment
		(start 243.842032 -104.493568)
		(end 243.842032 -105.3084)
		(width 0.14732)
		(layer "In4.Cu")
		(net "CLK_25M_PCH_REF_NS_DP")
	)
	(segment
		(start 244.772942 -98.521774)
		(end 244.840252 -98.684334)
		(width 0.14732)
		(layer "In4.Cu")
		(net "CLK_25M_PCH_REF_NS_DP")
	)
	(segment
		(start 283.285184 -91.396058)
		(end 258.154932 -91.396058)
		(width 0.14732)
		(layer "In4.Cu")
		(net "CLK_25M_PCH_REF_NS_DP")
	)
	(segment
		(start 335.824322 -76.285344)
		(end 335.824322 -78.318614)
		(width 0.14732)
		(layer "In4.Cu")
		(net "CLK_25M_PCH_REF_NS_DP")
	)
	(segment
		(start 246.830088 -108.296456)
		(end 247.0277 -108.296456)
		(width 0.14732)
		(layer "In4.Cu")
		(net "CLK_25M_PCH_REF_NS_DP")
	)
	(segment
		(start 336.41538 -79.74584)
		(end 336.41538 -81.524348)
		(width 0.14732)
		(layer "In4.Cu")
		(net "CLK_25M_PCH_REF_NS_DP")
	)
	(segment
		(start 248.00687 -109.275626)
		(end 248.00687 -109.473238)
		(width 0.14732)
		(layer "In4.Cu")
		(net "CLK_25M_PCH_REF_NS_DP")
	)
	(segment
		(start 336.41538 -81.524348)
		(end 335.055464 -82.884264)
		(width 0.14732)
		(layer "In4.Cu")
		(net "CLK_25M_PCH_REF_NS_DP")
	)
	(segment
		(start 245.20271 -97.484438)
		(end 245.27002 -97.646998)
		(width 0.14732)
		(layer "In4.Cu")
		(net "CLK_25M_PCH_REF_NS_DP")
	)
	(segment
		(start 332.273148 -84.035392)
		(end 325.805292 -85.321648)
		(width 0.14732)
		(layer "In4.Cu")
		(net "CLK_25M_PCH_REF_NS_DP")
	)
	(segment
		(start 244.840252 -98.684334)
		(end 244.67312 -99.088194)
		(width 0.14732)
		(layer "In4.Cu")
		(net "CLK_25M_PCH_REF_NS_DP")
	)
	(segment
		(start 244.67439 -106.140758)
		(end 244.872002 -106.140758)
		(width 0.14732)
		(layer "In4.Cu")
		(net "CLK_25M_PCH_REF_NS_DP")
	)
	(segment
		(start 246.309134 -107.57789)
		(end 246.569738 -107.838494)
		(width 0.14732)
		(layer "In4.Cu")
		(net "CLK_25M_PCH_REF_NS_DP")
	)
	(segment
		(start 248.00687 -109.473238)
		(end 248.26722 -109.733588)
		(width 0.14732)
		(layer "In4.Cu")
		(net "CLK_25M_PCH_REF_NS_DP")
	)
	(segment
		(start 245.27002 -97.646998)
		(end 245.102888 -98.050858)
		(width 0.14732)
		(layer "In4.Cu")
		(net "CLK_25M_PCH_REF_NS_DP")
	)
	(segment
		(start 247.94718 -93.475048)
		(end 246.097044 -95.325184)
		(width 0.14732)
		(layer "In4.Cu")
		(net "CLK_25M_PCH_REF_NS_DP")
	)
	(segment
		(start 248.725436 -110.191804)
		(end 248.985786 -110.452154)
		(width 0.14732)
		(layer "In4.Cu")
		(net "CLK_25M_PCH_REF_NS_DP")
	)
	(segment
		(start 245.102888 -98.050858)
		(end 244.940074 -98.118168)
		(width 0.14732)
		(layer "In4.Cu")
		(net "CLK_25M_PCH_REF_NS_DP")
	)
	(segment
		(start 244.510306 -99.155504)
		(end 243.842032 -100.768912)
		(width 0.14732)
		(layer "In4.Cu")
		(net "CLK_25M_PCH_REF_NS_DP")
	)
	(segment
		(start 251.3584 -108.984034)
		(end 251.3584 -109.208062)
		(width 0.13208)
		(layer "F.Cu")
		(net "CLK_25M_PCH_REF_NS_DN")
	)
	(segment
		(start 338.305394 -58.355992)
		(end 338.149692 -58.610246)
		(width 0.0889)
		(layer "F.Cu")
		(net "CLK_25M_PCH_REF_NS_DN")
	)
	(segment
		(start 335.565496 -75.68057)
		(end 335.255362 -75.990704)
		(width 0.13208)
		(layer "F.Cu")
		(net "CLK_25M_PCH_REF_NS_DN")
	)
	(segment
		(start 338.072476 -70.591172)
		(end 337.937856 -70.916292)
		(width 0.13208)
		(layer "F.Cu")
		(net "CLK_25M_PCH_REF_NS_DN")
	)
	(segment
		(start 338.072476 -66.391028)
		(end 338.072476 -66.413126)
		(width 0.0889)
		(layer "F.Cu")
		(net "CLK_25M_PCH_REF_NS_DN")
	)
	(segment
		(start 251.3584 -109.208062)
		(end 251.67336 -109.523022)
		(width 0.13208)
		(layer "F.Cu")
		(net "CLK_25M_PCH_REF_NS_DN")
	)
	(segment
		(start 251.74956 -108.592874)
		(end 251.3584 -108.984034)
		(width 0.13208)
		(layer "F.Cu")
		(net "CLK_25M_PCH_REF_NS_DN")
	)
	(segment
		(start 338.100416 -58.989214)
		(end 338.210144 -59.098942)
		(width 0.0889)
		(layer "F.Cu")
		(net "CLK_25M_PCH_REF_NS_DN")
	)
	(segment
		(start 338.4296 -65.46977)
		(end 338.10702 -65.79235)
		(width 0.0889)
		(layer "F.Cu")
		(net "CLK_25M_PCH_REF_NS_DN")
	)
	(segment
		(start 338.210144 -59.37123)
		(end 338.132674 -59.4487)
		(width 0.0889)
		(layer "F.Cu")
		(net "CLK_25M_PCH_REF_NS_DN")
	)
	(segment
		(start 338.4296 -60.266326)
		(end 338.4296 -65.46977)
		(width 0.0889)
		(layer "F.Cu")
		(net "CLK_25M_PCH_REF_NS_DN")
	)
	(segment
		(start 338.10702 -65.79235)
		(end 338.10702 -66.356484)
		(width 0.0889)
		(layer "F.Cu")
		(net "CLK_25M_PCH_REF_NS_DN")
	)
	(segment
		(start 338.072476 -66.413126)
		(end 338.072476 -70.591172)
		(width 0.13208)
		(layer "F.Cu")
		(net "CLK_25M_PCH_REF_NS_DN")
	)
	(segment
		(start 338.149692 -58.610246)
		(end 338.100416 -58.784998)
		(width 0.0889)
		(layer "F.Cu")
		(net "CLK_25M_PCH_REF_NS_DN")
	)
	(segment
		(start 338.132674 -59.4487)
		(end 338.132674 -59.9694)
		(width 0.0889)
		(layer "F.Cu")
		(net "CLK_25M_PCH_REF_NS_DN")
	)
	(segment
		(start 338.10702 -66.356484)
		(end 338.072476 -66.391028)
		(width 0.0889)
		(layer "F.Cu")
		(net "CLK_25M_PCH_REF_NS_DN")
	)
	(segment
		(start 338.40039 -58.020204)
		(end 338.305394 -58.355992)
		(width 0.0889)
		(layer "F.Cu")
		(net "CLK_25M_PCH_REF_NS_DN")
	)
	(segment
		(start 337.937856 -70.916292)
		(end 335.565496 -73.288652)
		(width 0.13208)
		(layer "F.Cu")
		(net "CLK_25M_PCH_REF_NS_DN")
	)
	(segment
		(start 335.565496 -73.288652)
		(end 335.565496 -75.68057)
		(width 0.13208)
		(layer "F.Cu")
		(net "CLK_25M_PCH_REF_NS_DN")
	)
	(segment
		(start 338.100416 -58.784998)
		(end 338.100416 -58.989214)
		(width 0.0889)
		(layer "F.Cu")
		(net "CLK_25M_PCH_REF_NS_DN")
	)
	(segment
		(start 338.210144 -59.098942)
		(end 338.210144 -59.37123)
		(width 0.0889)
		(layer "F.Cu")
		(net "CLK_25M_PCH_REF_NS_DN")
	)
	(segment
		(start 338.132674 -59.9694)
		(end 338.4296 -60.266326)
		(width 0.0889)
		(layer "F.Cu")
		(net "CLK_25M_PCH_REF_NS_DN")
	)
	(via
		(at 251.67336 -109.523022)
		(size 0.508)
		(drill 0.254)
		(layers "F.Cu" "B.Cu")
		(net "CLK_25M_PCH_REF_NS_DN")
	)
	(via
		(at 335.255362 -75.990704)
		(size 0.508)
		(drill 0.254)
		(layers "F.Cu" "B.Cu")
		(net "CLK_25M_PCH_REF_NS_DN")
	)
	(segment
		(start 320.839592 -85.047328)
		(end 305.582574 -88.08212)
		(width 0.14732)
		(layer "In4.Cu")
		(net "CLK_25M_PCH_REF_NS_DN")
	)
	(segment
		(start 283.230574 -91.121738)
		(end 258.100322 -91.121738)
		(width 0.14732)
		(layer "In4.Cu")
		(net "CLK_25M_PCH_REF_NS_DN")
	)
	(segment
		(start 251.37872 -110.139988)
		(end 251.37872 -109.817662)
		(width 0.14732)
		(layer "In4.Cu")
		(net "CLK_25M_PCH_REF_NS_DN")
	)
	(segment
		(start 245.86438 -95.169736)
		(end 243.567712 -100.714302)
		(width 0.14732)
		(layer "In4.Cu")
		(net "CLK_25M_PCH_REF_NS_DN")
	)
	(segment
		(start 250.792234 -110.726474)
		(end 251.37872 -110.139988)
		(width 0.14732)
		(layer "In4.Cu")
		(net "CLK_25M_PCH_REF_NS_DN")
	)
	(segment
		(start 243.567712 -105.422192)
		(end 248.871994 -110.726474)
		(width 0.14732)
		(layer "In4.Cu")
		(net "CLK_25M_PCH_REF_NS_DN")
	)
	(segment
		(start 335.255362 -75.990704)
		(end 335.550002 -76.285344)
		(width 0.14732)
		(layer "In4.Cu")
		(net "CLK_25M_PCH_REF_NS_DN")
	)
	(segment
		(start 335.550002 -76.285344)
		(end 335.550002 -78.373224)
		(width 0.14732)
		(layer "In4.Cu")
		(net "CLK_25M_PCH_REF_NS_DN")
	)
	(segment
		(start 248.871994 -110.726474)
		(end 250.792234 -110.726474)
		(width 0.14732)
		(layer "In4.Cu")
		(net "CLK_25M_PCH_REF_NS_DN")
	)
	(segment
		(start 243.567712 -100.714302)
		(end 243.567712 -105.422192)
		(width 0.14732)
		(layer "In4.Cu")
		(net "CLK_25M_PCH_REF_NS_DN")
	)
	(segment
		(start 334.900016 -82.6516)
		(end 332.193138 -83.771486)
		(width 0.14732)
		(layer "In4.Cu")
		(net "CLK_25M_PCH_REF_NS_DN")
	)
	(segment
		(start 305.582574 -88.08212)
		(end 303.20996 -89.064846)
		(width 0.14732)
		(layer "In4.Cu")
		(net "CLK_25M_PCH_REF_NS_DN")
	)
	(segment
		(start 335.550002 -78.373224)
		(end 336.14106 -79.80045)
		(width 0.14732)
		(layer "In4.Cu")
		(net "CLK_25M_PCH_REF_NS_DN")
	)
	(segment
		(start 247.833388 -93.200728)
		(end 245.86438 -95.169736)
		(width 0.14732)
		(layer "In4.Cu")
		(net "CLK_25M_PCH_REF_NS_DN")
	)
	(segment
		(start 255.906016 -92.03055)
		(end 251.462286 -92.03055)
		(width 0.14732)
		(layer "In4.Cu")
		(net "CLK_25M_PCH_REF_NS_DN")
	)
	(segment
		(start 336.14106 -81.410556)
		(end 334.900016 -82.6516)
		(width 0.14732)
		(layer "In4.Cu")
		(net "CLK_25M_PCH_REF_NS_DN")
	)
	(segment
		(start 250.292108 -93.200728)
		(end 247.833388 -93.200728)
		(width 0.14732)
		(layer "In4.Cu")
		(net "CLK_25M_PCH_REF_NS_DN")
	)
	(segment
		(start 251.37872 -109.817662)
		(end 251.67336 -109.523022)
		(width 0.14732)
		(layer "In4.Cu")
		(net "CLK_25M_PCH_REF_NS_DN")
	)
	(segment
		(start 336.14106 -79.80045)
		(end 336.14106 -81.410556)
		(width 0.14732)
		(layer "In4.Cu")
		(net "CLK_25M_PCH_REF_NS_DN")
	)
	(segment
		(start 251.462286 -92.03055)
		(end 250.292108 -93.200728)
		(width 0.14732)
		(layer "In4.Cu")
		(net "CLK_25M_PCH_REF_NS_DN")
	)
	(segment
		(start 325.778114 -85.047328)
		(end 320.839592 -85.047328)
		(width 0.14732)
		(layer "In4.Cu")
		(net "CLK_25M_PCH_REF_NS_DN")
	)
	(segment
		(start 303.20996 -89.064846)
		(end 288.196528 -89.064846)
		(width 0.14732)
		(layer "In4.Cu")
		(net "CLK_25M_PCH_REF_NS_DN")
	)
	(segment
		(start 258.100322 -91.121738)
		(end 255.906016 -92.03055)
		(width 0.14732)
		(layer "In4.Cu")
		(net "CLK_25M_PCH_REF_NS_DN")
	)
	(segment
		(start 332.193138 -83.771486)
		(end 325.778114 -85.047328)
		(width 0.14732)
		(layer "In4.Cu")
		(net "CLK_25M_PCH_REF_NS_DN")
	)
	(segment
		(start 288.196528 -89.064846)
		(end 283.230574 -91.121738)
		(width 0.14732)
		(layer "In4.Cu")
		(net "CLK_25M_PCH_REF_NS_DN")
	)
	(segment
		(start 340.12124 -65.384934)
		(end 340.12124 -64.010032)
		(width 0.0889)
		(layer "F.Cu")
		(net "CLK_25M_PCH_CPU1_DP")
	)
	(segment
		(start 340.08949 -72.90054)
		(end 340.08949 -71.896224)
		(width 0.13208)
		(layer "F.Cu")
		(net "CLK_25M_PCH_CPU1_DP")
	)
	(segment
		(start 339.901276 -59.639962)
		(end 339.901276 -59.265312)
		(width 0.0889)
		(layer "F.Cu")
		(net "CLK_25M_PCH_CPU1_DP")
	)
	(segment
		(start 340.12124 -61.350144)
		(end 340.12124 -59.859926)
		(width 0.0889)
		(layer "F.Cu")
		(net "CLK_25M_PCH_CPU1_DP")
	)
	(segment
		(start 340.448646 -67.500246)
		(end 340.448646 -67.104006)
		(width 0.13208)
		(layer "F.Cu")
		(net "CLK_25M_PCH_CPU1_DP")
	)
	(segment
		(start 340.21141 -73.4187)
		(end 340.21141 -73.02246)
		(width 0.13208)
		(layer "F.Cu")
		(net "CLK_25M_PCH_CPU1_DP")
	)
	(segment
		(start 340.570566 -68.658486)
		(end 340.448646 -68.536566)
		(width 0.13208)
		(layer "F.Cu")
		(net "CLK_25M_PCH_CPU1_DP")
	)
	(segment
		(start 340.414356 -66.011298)
		(end 340.414356 -65.67805)
		(width 0.0889)
		(layer "F.Cu")
		(net "CLK_25M_PCH_CPU1_DP")
	)
	(segment
		(start 340.448646 -68.140326)
		(end 340.570566 -68.018406)
		(width 0.13208)
		(layer "F.Cu")
		(net "CLK_25M_PCH_CPU1_DP")
	)
	(segment
		(start 340.414356 -65.67805)
		(end 340.12124 -65.384934)
		(width 0.0889)
		(layer "F.Cu")
		(net "CLK_25M_PCH_CPU1_DP")
	)
	(segment
		(start 340.570566 -67.622166)
		(end 340.448646 -67.500246)
		(width 0.13208)
		(layer "F.Cu")
		(net "CLK_25M_PCH_CPU1_DP")
	)
	(segment
		(start 340.570566 -66.585846)
		(end 340.448646 -66.463926)
		(width 0.13208)
		(layer "F.Cu")
		(net "CLK_25M_PCH_CPU1_DP")
	)
	(segment
		(start 340.400894 -74.524616)
		(end 340.08949 -74.213212)
		(width 0.13208)
		(layer "F.Cu")
		(net "CLK_25M_PCH_CPU1_DP")
	)
	(segment
		(start 340.448646 -68.536566)
		(end 340.448646 -68.140326)
		(width 0.13208)
		(layer "F.Cu")
		(net "CLK_25M_PCH_CPU1_DP")
	)
	(segment
		(start 340.121494 -61.904118)
		(end 340.121494 -61.726318)
		(width 0.0889)
		(layer "F.Cu")
		(net "CLK_25M_PCH_CPU1_DP")
	)
	(segment
		(start 340.570566 -69.694806)
		(end 340.448646 -69.572886)
		(width 0.13208)
		(layer "F.Cu")
		(net "CLK_25M_PCH_CPU1_DP")
	)
	(segment
		(start 340.220554 -62.003178)
		(end 340.121494 -61.904118)
		(width 0.0889)
		(layer "F.Cu")
		(net "CLK_25M_PCH_CPU1_DP")
	)
	(segment
		(start 340.220554 -61.449458)
		(end 340.12124 -61.350144)
		(width 0.0889)
		(layer "F.Cu")
		(net "CLK_25M_PCH_CPU1_DP")
	)
	(segment
		(start 340.448646 -66.067686)
		(end 340.448646 -66.045588)
		(width 0.0889)
		(layer "F.Cu")
		(net "CLK_25M_PCH_CPU1_DP")
	)
	(segment
		(start 340.12124 -63.433452)
		(end 340.21903 -63.335662)
		(width 0.0889)
		(layer "F.Cu")
		(net "CLK_25M_PCH_CPU1_DP")
	)
	(segment
		(start 340.08949 -73.54062)
		(end 340.21141 -73.4187)
		(width 0.13208)
		(layer "F.Cu")
		(net "CLK_25M_PCH_CPU1_DP")
	)
	(segment
		(start 340.12124 -64.010032)
		(end 340.21903 -63.912242)
		(width 0.0889)
		(layer "F.Cu")
		(net "CLK_25M_PCH_CPU1_DP")
	)
	(segment
		(start 340.08949 -71.896224)
		(end 340.448646 -71.029068)
		(width 0.13208)
		(layer "F.Cu")
		(net "CLK_25M_PCH_CPU1_DP")
	)
	(segment
		(start 340.21903 -62.759082)
		(end 340.21903 -62.568582)
		(width 0.0889)
		(layer "F.Cu")
		(net "CLK_25M_PCH_CPU1_DP")
	)
	(segment
		(start 340.570566 -68.018406)
		(end 340.570566 -67.622166)
		(width 0.13208)
		(layer "F.Cu")
		(net "CLK_25M_PCH_CPU1_DP")
	)
	(segment
		(start 340.12124 -62.280292)
		(end 340.220554 -62.180978)
		(width 0.0889)
		(layer "F.Cu")
		(net "CLK_25M_PCH_CPU1_DP")
	)
	(segment
		(start 340.21903 -62.568582)
		(end 340.12124 -62.470792)
		(width 0.0889)
		(layer "F.Cu")
		(net "CLK_25M_PCH_CPU1_DP")
	)
	(segment
		(start 340.448646 -71.029068)
		(end 340.448646 -70.212966)
		(width 0.13208)
		(layer "F.Cu")
		(net "CLK_25M_PCH_CPU1_DP")
	)
	(segment
		(start 340.570566 -70.091046)
		(end 340.570566 -69.694806)
		(width 0.13208)
		(layer "F.Cu")
		(net "CLK_25M_PCH_CPU1_DP")
	)
	(segment
		(start 340.12124 -62.470792)
		(end 340.12124 -62.280292)
		(width 0.0889)
		(layer "F.Cu")
		(net "CLK_25M_PCH_CPU1_DP")
	)
	(segment
		(start 340.570566 -69.054726)
		(end 340.570566 -68.658486)
		(width 0.13208)
		(layer "F.Cu")
		(net "CLK_25M_PCH_CPU1_DP")
	)
	(segment
		(start 340.121494 -61.726318)
		(end 340.220554 -61.627258)
		(width 0.0889)
		(layer "F.Cu")
		(net "CLK_25M_PCH_CPU1_DP")
	)
	(segment
		(start 340.220554 -62.180978)
		(end 340.220554 -62.003178)
		(width 0.0889)
		(layer "F.Cu")
		(net "CLK_25M_PCH_CPU1_DP")
	)
	(segment
		(start 340.12124 -59.859926)
		(end 339.901276 -59.639962)
		(width 0.0889)
		(layer "F.Cu")
		(net "CLK_25M_PCH_CPU1_DP")
	)
	(segment
		(start 340.570566 -66.982086)
		(end 340.570566 -66.585846)
		(width 0.13208)
		(layer "F.Cu")
		(net "CLK_25M_PCH_CPU1_DP")
	)
	(segment
		(start 340.21903 -63.912242)
		(end 340.21903 -63.721742)
		(width 0.0889)
		(layer "F.Cu")
		(net "CLK_25M_PCH_CPU1_DP")
	)
	(segment
		(start 340.12124 -62.856872)
		(end 340.21903 -62.759082)
		(width 0.0889)
		(layer "F.Cu")
		(net "CLK_25M_PCH_CPU1_DP")
	)
	(segment
		(start 340.448646 -69.572886)
		(end 340.448646 -69.176646)
		(width 0.13208)
		(layer "F.Cu")
		(net "CLK_25M_PCH_CPU1_DP")
	)
	(segment
		(start 340.08949 -74.213212)
		(end 340.08949 -73.54062)
		(width 0.13208)
		(layer "F.Cu")
		(net "CLK_25M_PCH_CPU1_DP")
	)
	(segment
		(start 340.448646 -69.176646)
		(end 340.570566 -69.054726)
		(width 0.13208)
		(layer "F.Cu")
		(net "CLK_25M_PCH_CPU1_DP")
	)
	(segment
		(start 340.21903 -63.335662)
		(end 340.21903 -63.145162)
		(width 0.0889)
		(layer "F.Cu")
		(net "CLK_25M_PCH_CPU1_DP")
	)
	(segment
		(start 340.448646 -66.045588)
		(end 340.414356 -66.011298)
		(width 0.0889)
		(layer "F.Cu")
		(net "CLK_25M_PCH_CPU1_DP")
	)
	(segment
		(start 340.21903 -63.721742)
		(end 340.12124 -63.623952)
		(width 0.0889)
		(layer "F.Cu")
		(net "CLK_25M_PCH_CPU1_DP")
	)
	(segment
		(start 340.12124 -63.047372)
		(end 340.12124 -62.856872)
		(width 0.0889)
		(layer "F.Cu")
		(net "CLK_25M_PCH_CPU1_DP")
	)
	(segment
		(start 340.448646 -67.104006)
		(end 340.570566 -66.982086)
		(width 0.13208)
		(layer "F.Cu")
		(net "CLK_25M_PCH_CPU1_DP")
	)
	(segment
		(start 340.448646 -70.212966)
		(end 340.570566 -70.091046)
		(width 0.13208)
		(layer "F.Cu")
		(net "CLK_25M_PCH_CPU1_DP")
	)
	(segment
		(start 340.21141 -73.02246)
		(end 340.08949 -72.90054)
		(width 0.13208)
		(layer "F.Cu")
		(net "CLK_25M_PCH_CPU1_DP")
	)
	(segment
		(start 340.21903 -63.145162)
		(end 340.12124 -63.047372)
		(width 0.0889)
		(layer "F.Cu")
		(net "CLK_25M_PCH_CPU1_DP")
	)
	(segment
		(start 340.220554 -61.627258)
		(end 340.220554 -61.449458)
		(width 0.0889)
		(layer "F.Cu")
		(net "CLK_25M_PCH_CPU1_DP")
	)
	(segment
		(start 340.12124 -63.623952)
		(end 340.12124 -63.433452)
		(width 0.0889)
		(layer "F.Cu")
		(net "CLK_25M_PCH_CPU1_DP")
	)
	(segment
		(start 340.448646 -66.463926)
		(end 340.448646 -66.067686)
		(width 0.13208)
		(layer "F.Cu")
		(net "CLK_25M_PCH_CPU1_DP")
	)
	(via
		(at 239.0267 -134.328408)
		(size 0.508)
		(drill 0.254)
		(layers "F.Cu" "B.Cu")
		(net "CLK_25M_PCH_CPU1_DP")
	)
	(via
		(at 340.400894 -74.524616)
		(size 0.508)
		(drill 0.254)
		(layers "F.Cu" "B.Cu")
		(net "CLK_25M_PCH_CPU1_DP")
	)
	(segment
		(start 239.0267 -134.328408)
		(end 238.74984 -134.605268)
		(width 0.13208)
		(layer "B.Cu")
		(net "CLK_25M_PCH_CPU1_DP")
	)
	(segment
		(start 238.36122 -134.605268)
		(end 237.804706 -134.048754)
		(width 0.13208)
		(layer "B.Cu")
		(net "CLK_25M_PCH_CPU1_DP")
	)
	(segment
		(start 237.804706 -134.048754)
		(end 237.382304 -134.048754)
		(width 0.13208)
		(layer "B.Cu")
		(net "CLK_25M_PCH_CPU1_DP")
	)
	(segment
		(start 238.74984 -134.605268)
		(end 238.36122 -134.605268)
		(width 0.13208)
		(layer "B.Cu")
		(net "CLK_25M_PCH_CPU1_DP")
	)
	(segment
		(start 336.006948 -72.972168)
		(end 333.58328 -75.395836)
		(width 0.14732)
		(layer "In4.Cu")
		(net "CLK_25M_PCH_CPU1_DP")
	)
	(segment
		(start 239.518952 -133.686042)
		(end 239.70742 -134.038594)
		(width 0.14732)
		(layer "In4.Cu")
		(net "CLK_25M_PCH_CPU1_DP")
	)
	(segment
		(start 247.93575 -90.929206)
		(end 225.691954 -113.173002)
		(width 0.14732)
		(layer "In4.Cu")
		(net "CLK_25M_PCH_CPU1_DP")
	)
	(segment
		(start 239.3188 -134.620508)
		(end 239.0267 -134.328408)
		(width 0.14732)
		(layer "In4.Cu")
		(net "CLK_25M_PCH_CPU1_DP")
	)
	(segment
		(start 304.712878 -87.24392)
		(end 302.407828 -88.198706)
		(width 0.14732)
		(layer "In4.Cu")
		(net "CLK_25M_PCH_CPU1_DP")
	)
	(segment
		(start 302.407828 -88.198706)
		(end 254.527812 -88.198706)
		(width 0.14732)
		(layer "In4.Cu")
		(net "CLK_25M_PCH_CPU1_DP")
	)
	(segment
		(start 330.121768 -82.489548)
		(end 326.03821 -84.181188)
		(width 0.14732)
		(layer "In4.Cu")
		(net "CLK_25M_PCH_CPU1_DP")
	)
	(segment
		(start 231.66832 -129.118868)
		(end 232.849928 -130.300476)
		(width 0.14732)
		(layer "In4.Cu")
		(net "CLK_25M_PCH_CPU1_DP")
	)
	(segment
		(start 239.532414 -134.620508)
		(end 239.3188 -134.620508)
		(width 0.14732)
		(layer "In4.Cu")
		(net "CLK_25M_PCH_CPU1_DP")
	)
	(segment
		(start 223.24822 -125.23216)
		(end 227.134928 -129.118868)
		(width 0.14732)
		(layer "In4.Cu")
		(net "CLK_25M_PCH_CPU1_DP")
	)
	(segment
		(start 320.110612 -84.181188)
		(end 304.712878 -87.24392)
		(width 0.14732)
		(layer "In4.Cu")
		(net "CLK_25M_PCH_CPU1_DP")
	)
	(segment
		(start 340.400894 -74.524616)
		(end 340.106254 -74.229976)
		(width 0.14732)
		(layer "In4.Cu")
		(net "CLK_25M_PCH_CPU1_DP")
	)
	(segment
		(start 223.24822 -119.072406)
		(end 223.24822 -125.23216)
		(width 0.14732)
		(layer "In4.Cu")
		(net "CLK_25M_PCH_CPU1_DP")
	)
	(segment
		(start 254.527812 -88.198706)
		(end 247.93575 -90.929206)
		(width 0.14732)
		(layer "In4.Cu")
		(net "CLK_25M_PCH_CPU1_DP")
	)
	(segment
		(start 339.620352 -72.972168)
		(end 336.006948 -72.972168)
		(width 0.14732)
		(layer "In4.Cu")
		(net "CLK_25M_PCH_CPU1_DP")
	)
	(segment
		(start 238.02975 -132.837682)
		(end 238.393224 -133.080506)
		(width 0.14732)
		(layer "In4.Cu")
		(net "CLK_25M_PCH_CPU1_DP")
	)
	(segment
		(start 333.58328 -77.709522)
		(end 332.650592 -79.960724)
		(width 0.14732)
		(layer "In4.Cu")
		(net "CLK_25M_PCH_CPU1_DP")
	)
	(segment
		(start 227.134928 -129.118868)
		(end 231.66832 -129.118868)
		(width 0.14732)
		(layer "In4.Cu")
		(net "CLK_25M_PCH_CPU1_DP")
	)
	(segment
		(start 238.562388 -133.046978)
		(end 239.518952 -133.686042)
		(width 0.14732)
		(layer "In4.Cu")
		(net "CLK_25M_PCH_CPU1_DP")
	)
	(segment
		(start 237.064296 -132.045964)
		(end 237.996222 -132.668518)
		(width 0.14732)
		(layer "In4.Cu")
		(net "CLK_25M_PCH_CPU1_DP")
	)
	(segment
		(start 239.70742 -134.445502)
		(end 239.532414 -134.620508)
		(width 0.14732)
		(layer "In4.Cu")
		(net "CLK_25M_PCH_CPU1_DP")
	)
	(segment
		(start 239.70742 -134.038594)
		(end 239.70742 -134.445502)
		(width 0.14732)
		(layer "In4.Cu")
		(net "CLK_25M_PCH_CPU1_DP")
	)
	(segment
		(start 237.996222 -132.668518)
		(end 238.02975 -132.837682)
		(width 0.14732)
		(layer "In4.Cu")
		(net "CLK_25M_PCH_CPU1_DP")
	)
	(segment
		(start 340.106254 -73.45807)
		(end 339.620352 -72.972168)
		(width 0.14732)
		(layer "In4.Cu")
		(net "CLK_25M_PCH_CPU1_DP")
	)
	(segment
		(start 326.03821 -84.181188)
		(end 320.110612 -84.181188)
		(width 0.14732)
		(layer "In4.Cu")
		(net "CLK_25M_PCH_CPU1_DP")
	)
	(segment
		(start 225.691954 -113.173002)
		(end 223.24822 -119.072406)
		(width 0.14732)
		(layer "In4.Cu")
		(net "CLK_25M_PCH_CPU1_DP")
	)
	(segment
		(start 232.849928 -130.300476)
		(end 237.064296 -132.045964)
		(width 0.14732)
		(layer "In4.Cu")
		(net "CLK_25M_PCH_CPU1_DP")
	)
	(segment
		(start 333.58328 -75.395836)
		(end 333.58328 -77.709522)
		(width 0.14732)
		(layer "In4.Cu")
		(net "CLK_25M_PCH_CPU1_DP")
	)
	(segment
		(start 340.106254 -74.229976)
		(end 340.106254 -73.45807)
		(width 0.14732)
		(layer "In4.Cu")
		(net "CLK_25M_PCH_CPU1_DP")
	)
	(segment
		(start 238.393224 -133.080506)
		(end 238.562388 -133.046978)
		(width 0.14732)
		(layer "In4.Cu")
		(net "CLK_25M_PCH_CPU1_DP")
	)
	(segment
		(start 332.650592 -79.960724)
		(end 330.121768 -82.489548)
		(width 0.14732)
		(layer "In4.Cu")
		(net "CLK_25M_PCH_CPU1_DP")
	)
	(segment
		(start 339.537294 -74.524616)
		(end 339.83041 -74.2315)
		(width 0.13208)
		(layer "F.Cu")
		(net "CLK_25M_PCH_CPU1_DN")
	)
	(segment
		(start 340.189566 -66.045588)
		(end 340.22411 -66.011044)
		(width 0.0889)
		(layer "F.Cu")
		(net "CLK_25M_PCH_CPU1_DN")
	)
	(segment
		(start 339.83041 -74.2315)
		(end 339.83041 -71.844662)
		(width 0.13208)
		(layer "F.Cu")
		(net "CLK_25M_PCH_CPU1_DN")
	)
	(segment
		(start 339.710776 -59.718702)
		(end 339.710776 -59.513724)
		(width 0.0889)
		(layer "F.Cu")
		(net "CLK_25M_PCH_CPU1_DN")
	)
	(segment
		(start 339.930994 -59.93892)
		(end 339.710776 -59.718702)
		(width 0.0889)
		(layer "F.Cu")
		(net "CLK_25M_PCH_CPU1_DN")
	)
	(segment
		(start 339.930994 -65.463928)
		(end 339.930994 -59.93892)
		(width 0.0889)
		(layer "F.Cu")
		(net "CLK_25M_PCH_CPU1_DN")
	)
	(segment
		(start 340.22411 -66.011044)
		(end 340.22411 -65.757044)
		(width 0.0889)
		(layer "F.Cu")
		(net "CLK_25M_PCH_CPU1_DN")
	)
	(segment
		(start 340.189566 -66.067686)
		(end 340.189566 -66.045588)
		(width 0.0889)
		(layer "F.Cu")
		(net "CLK_25M_PCH_CPU1_DN")
	)
	(segment
		(start 340.22411 -65.757044)
		(end 339.930994 -65.463928)
		(width 0.0889)
		(layer "F.Cu")
		(net "CLK_25M_PCH_CPU1_DN")
	)
	(segment
		(start 340.189566 -70.977506)
		(end 340.189566 -66.067686)
		(width 0.13208)
		(layer "F.Cu")
		(net "CLK_25M_PCH_CPU1_DN")
	)
	(segment
		(start 339.80628 -58.771028)
		(end 339.901276 -58.43524)
		(width 0.0889)
		(layer "F.Cu")
		(net "CLK_25M_PCH_CPU1_DN")
	)
	(segment
		(start 339.710776 -59.513724)
		(end 339.593174 -59.396122)
		(width 0.0889)
		(layer "F.Cu")
		(net "CLK_25M_PCH_CPU1_DN")
	)
	(segment
		(start 339.593174 -59.119008)
		(end 339.80628 -58.771028)
		(width 0.0889)
		(layer "F.Cu")
		(net "CLK_25M_PCH_CPU1_DN")
	)
	(segment
		(start 339.593174 -59.396122)
		(end 339.593174 -59.119008)
		(width 0.0889)
		(layer "F.Cu")
		(net "CLK_25M_PCH_CPU1_DN")
	)
	(segment
		(start 339.83041 -71.844662)
		(end 340.189566 -70.977506)
		(width 0.13208)
		(layer "F.Cu")
		(net "CLK_25M_PCH_CPU1_DN")
	)
	(via
		(at 239.0267 -135.192008)
		(size 0.508)
		(drill 0.254)
		(layers "F.Cu" "B.Cu")
		(net "CLK_25M_PCH_CPU1_DN")
	)
	(via
		(at 339.537294 -74.524616)
		(size 0.508)
		(drill 0.254)
		(layers "F.Cu" "B.Cu")
		(net "CLK_25M_PCH_CPU1_DN")
	)
	(segment
		(start 237.86211 -135.401558)
		(end 237.401862 -135.401558)
		(width 0.13208)
		(layer "B.Cu")
		(net "CLK_25M_PCH_CPU1_DN")
	)
	(segment
		(start 238.69904 -134.864348)
		(end 238.39932 -134.864348)
		(width 0.13208)
		(layer "B.Cu")
		(net "CLK_25M_PCH_CPU1_DN")
	)
	(segment
		(start 238.39932 -134.864348)
		(end 237.86211 -135.401558)
		(width 0.13208)
		(layer "B.Cu")
		(net "CLK_25M_PCH_CPU1_DN")
	)
	(segment
		(start 239.0267 -135.192008)
		(end 238.69904 -134.864348)
		(width 0.13208)
		(layer "B.Cu")
		(net "CLK_25M_PCH_CPU1_DN")
	)
	(segment
		(start 225.924618 -113.32845)
		(end 223.52254 -119.127016)
		(width 0.14732)
		(layer "In4.Cu")
		(net "CLK_25M_PCH_CPU1_DN")
	)
	(segment
		(start 334.924654 -74.442574)
		(end 334.924654 -74.61504)
		(width 0.14732)
		(layer "In4.Cu")
		(net "CLK_25M_PCH_CPU1_DN")
	)
	(segment
		(start 336.12074 -73.246488)
		(end 335.715102 -73.652126)
		(width 0.14732)
		(layer "In4.Cu")
		(net "CLK_25M_PCH_CPU1_DN")
	)
	(segment
		(start 239.98174 -134.559294)
		(end 239.646206 -134.894828)
		(width 0.14732)
		(layer "In4.Cu")
		(net "CLK_25M_PCH_CPU1_DN")
	)
	(segment
		(start 223.52254 -125.118368)
		(end 224.950528 -126.546356)
		(width 0.14732)
		(layer "In4.Cu")
		(net "CLK_25M_PCH_CPU1_DN")
	)
	(segment
		(start 334.44307 -74.924158)
		(end 333.8576 -75.509628)
		(width 0.14732)
		(layer "In4.Cu")
		(net "CLK_25M_PCH_CPU1_DN")
	)
	(segment
		(start 333.8576 -77.764132)
		(end 332.883256 -80.116172)
		(width 0.14732)
		(layer "In4.Cu")
		(net "CLK_25M_PCH_CPU1_DN")
	)
	(segment
		(start 239.32388 -134.894828)
		(end 239.0267 -135.192008)
		(width 0.14732)
		(layer "In4.Cu")
		(net "CLK_25M_PCH_CPU1_DN")
	)
	(segment
		(start 335.715102 -73.824592)
		(end 335.405984 -74.13371)
		(width 0.14732)
		(layer "In4.Cu")
		(net "CLK_25M_PCH_CPU1_DN")
	)
	(segment
		(start 333.8576 -76.172568)
		(end 333.97952 -76.294488)
		(width 0.14732)
		(layer "In4.Cu")
		(net "CLK_25M_PCH_CPU1_DN")
	)
	(segment
		(start 333.97952 -76.731368)
		(end 333.8576 -76.853288)
		(width 0.14732)
		(layer "In4.Cu")
		(net "CLK_25M_PCH_CPU1_DN")
	)
	(segment
		(start 333.8576 -75.509628)
		(end 333.8576 -76.172568)
		(width 0.14732)
		(layer "In4.Cu")
		(net "CLK_25M_PCH_CPU1_DN")
	)
	(segment
		(start 233.005376 -130.067812)
		(end 237.194344 -131.802886)
		(width 0.14732)
		(layer "In4.Cu")
		(net "CLK_25M_PCH_CPU1_DN")
	)
	(segment
		(start 335.715102 -73.652126)
		(end 335.715102 -73.824592)
		(width 0.14732)
		(layer "In4.Cu")
		(net "CLK_25M_PCH_CPU1_DN")
	)
	(segment
		(start 248.091198 -91.16187)
		(end 225.924618 -113.32845)
		(width 0.14732)
		(layer "In4.Cu")
		(net "CLK_25M_PCH_CPU1_DN")
	)
	(segment
		(start 339.831934 -74.229976)
		(end 339.831934 -73.571862)
		(width 0.14732)
		(layer "In4.Cu")
		(net "CLK_25M_PCH_CPU1_DN")
	)
	(segment
		(start 225.432112 -126.855474)
		(end 225.432112 -127.02794)
		(width 0.14732)
		(layer "In4.Cu")
		(net "CLK_25M_PCH_CPU1_DN")
	)
	(segment
		(start 223.52254 -119.127016)
		(end 223.52254 -125.118368)
		(width 0.14732)
		(layer "In4.Cu")
		(net "CLK_25M_PCH_CPU1_DN")
	)
	(segment
		(start 332.883256 -80.116172)
		(end 330.277216 -82.722212)
		(width 0.14732)
		(layer "In4.Cu")
		(net "CLK_25M_PCH_CPU1_DN")
	)
	(segment
		(start 334.924654 -74.61504)
		(end 334.615536 -74.924158)
		(width 0.14732)
		(layer "In4.Cu")
		(net "CLK_25M_PCH_CPU1_DN")
	)
	(segment
		(start 304.792888 -87.507826)
		(end 302.462438 -88.473026)
		(width 0.14732)
		(layer "In4.Cu")
		(net "CLK_25M_PCH_CPU1_DN")
	)
	(segment
		(start 338.88934 -73.246488)
		(end 338.76742 -73.368408)
		(width 0.14732)
		(layer "In4.Cu")
		(net "CLK_25M_PCH_CPU1_DN")
	)
	(segment
		(start 239.98174 -133.96976)
		(end 239.98174 -134.559294)
		(width 0.14732)
		(layer "In4.Cu")
		(net "CLK_25M_PCH_CPU1_DN")
	)
	(segment
		(start 225.122994 -126.546356)
		(end 225.432112 -126.855474)
		(width 0.14732)
		(layer "In4.Cu")
		(net "CLK_25M_PCH_CPU1_DN")
	)
	(segment
		(start 338.76742 -73.368408)
		(end 338.33054 -73.368408)
		(width 0.14732)
		(layer "In4.Cu")
		(net "CLK_25M_PCH_CPU1_DN")
	)
	(segment
		(start 254.582422 -88.473026)
		(end 248.091198 -91.16187)
		(width 0.14732)
		(layer "In4.Cu")
		(net "CLK_25M_PCH_CPU1_DN")
	)
	(segment
		(start 339.537294 -74.524616)
		(end 339.831934 -74.229976)
		(width 0.14732)
		(layer "In4.Cu")
		(net "CLK_25M_PCH_CPU1_DN")
	)
	(segment
		(start 334.615536 -74.924158)
		(end 334.44307 -74.924158)
		(width 0.14732)
		(layer "In4.Cu")
		(net "CLK_25M_PCH_CPU1_DN")
	)
	(segment
		(start 320.13779 -84.455508)
		(end 304.792888 -87.507826)
		(width 0.14732)
		(layer "In4.Cu")
		(net "CLK_25M_PCH_CPU1_DN")
	)
	(segment
		(start 239.646206 -134.894828)
		(end 239.32388 -134.894828)
		(width 0.14732)
		(layer "In4.Cu")
		(net "CLK_25M_PCH_CPU1_DN")
	)
	(segment
		(start 333.97952 -76.294488)
		(end 333.97952 -76.731368)
		(width 0.14732)
		(layer "In4.Cu")
		(net "CLK_25M_PCH_CPU1_DN")
	)
	(segment
		(start 227.24872 -128.844548)
		(end 231.782112 -128.844548)
		(width 0.14732)
		(layer "In4.Cu")
		(net "CLK_25M_PCH_CPU1_DN")
	)
	(segment
		(start 330.277216 -82.722212)
		(end 326.09282 -84.455508)
		(width 0.14732)
		(layer "In4.Cu")
		(net "CLK_25M_PCH_CPU1_DN")
	)
	(segment
		(start 338.20862 -73.246488)
		(end 336.12074 -73.246488)
		(width 0.14732)
		(layer "In4.Cu")
		(net "CLK_25M_PCH_CPU1_DN")
	)
	(segment
		(start 302.462438 -88.473026)
		(end 254.582422 -88.473026)
		(width 0.14732)
		(layer "In4.Cu")
		(net "CLK_25M_PCH_CPU1_DN")
	)
	(segment
		(start 225.432112 -127.02794)
		(end 227.24872 -128.844548)
		(width 0.14732)
		(layer "In4.Cu")
		(net "CLK_25M_PCH_CPU1_DN")
	)
	(segment
		(start 326.09282 -84.455508)
		(end 320.13779 -84.455508)
		(width 0.14732)
		(layer "In4.Cu")
		(net "CLK_25M_PCH_CPU1_DN")
	)
	(segment
		(start 333.8576 -76.853288)
		(end 333.8576 -77.764132)
		(width 0.14732)
		(layer "In4.Cu")
		(net "CLK_25M_PCH_CPU1_DN")
	)
	(segment
		(start 339.50656 -73.246488)
		(end 338.88934 -73.246488)
		(width 0.14732)
		(layer "In4.Cu")
		(net "CLK_25M_PCH_CPU1_DN")
	)
	(segment
		(start 239.728502 -133.49605)
		(end 239.98174 -133.96976)
		(width 0.14732)
		(layer "In4.Cu")
		(net "CLK_25M_PCH_CPU1_DN")
	)
	(segment
		(start 231.782112 -128.844548)
		(end 233.005376 -130.067812)
		(width 0.14732)
		(layer "In4.Cu")
		(net "CLK_25M_PCH_CPU1_DN")
	)
	(segment
		(start 335.405984 -74.13371)
		(end 335.233518 -74.13371)
		(width 0.14732)
		(layer "In4.Cu")
		(net "CLK_25M_PCH_CPU1_DN")
	)
	(segment
		(start 237.194344 -131.802886)
		(end 239.728502 -133.49605)
		(width 0.14732)
		(layer "In4.Cu")
		(net "CLK_25M_PCH_CPU1_DN")
	)
	(segment
		(start 224.950528 -126.546356)
		(end 225.122994 -126.546356)
		(width 0.14732)
		(layer "In4.Cu")
		(net "CLK_25M_PCH_CPU1_DN")
	)
	(segment
		(start 335.233518 -74.13371)
		(end 334.924654 -74.442574)
		(width 0.14732)
		(layer "In4.Cu")
		(net "CLK_25M_PCH_CPU1_DN")
	)
	(segment
		(start 338.33054 -73.368408)
		(end 338.20862 -73.246488)
		(width 0.14732)
		(layer "In4.Cu")
		(net "CLK_25M_PCH_CPU1_DN")
	)
	(segment
		(start 339.831934 -73.571862)
		(end 339.50656 -73.246488)
		(width 0.14732)
		(layer "In4.Cu")
		(net "CLK_25M_PCH_CPU1_DN")
	)
	(segment
		(start 339.463126 -63.406782)
		(end 339.366606 -63.310262)
		(width 0.0889)
		(layer "F.Cu")
		(net "CLK_25M_PCH_CPU0_DP")
	)
	(segment
		(start 337.518756 -74.563224)
		(end 337.485228 -74.563224)
		(width 0.13208)
		(layer "F.Cu")
		(net "CLK_25M_PCH_CPU0_DP")
	)
	(segment
		(start 339.524086 -68.001134)
		(end 339.524086 -67.620134)
		(width 0.13208)
		(layer "F.Cu")
		(net "CLK_25M_PCH_CPU0_DP")
	)
	(segment
		(start 338.845652 -71.698866)
		(end 339.224874 -71.319644)
		(width 0.13208)
		(layer "F.Cu")
		(net "CLK_25M_PCH_CPU0_DP")
	)
	(segment
		(start 339.463126 -62.705742)
		(end 339.366606 -62.609222)
		(width 0.0889)
		(layer "F.Cu")
		(net "CLK_25M_PCH_CPU0_DP")
	)
	(segment
		(start 339.399626 -67.495674)
		(end 339.399626 -67.114674)
		(width 0.13208)
		(layer "F.Cu")
		(net "CLK_25M_PCH_CPU0_DP")
	)
	(segment
		(start 339.366606 -63.310262)
		(end 339.366606 -63.056262)
		(width 0.0889)
		(layer "F.Cu")
		(net "CLK_25M_PCH_CPU0_DP")
	)
	(segment
		(start 339.366606 -61.908182)
		(end 339.366606 -61.654182)
		(width 0.0889)
		(layer "F.Cu")
		(net "CLK_25M_PCH_CPU0_DP")
	)
	(segment
		(start 339.366606 -60.212478)
		(end 339.400642 -60.129928)
		(width 0.0889)
		(layer "F.Cu")
		(net "CLK_25M_PCH_CPU0_DP")
	)
	(segment
		(start 337.779106 -72.94118)
		(end 338.055712 -72.664574)
		(width 0.13208)
		(layer "F.Cu")
		(net "CLK_25M_PCH_CPU0_DP")
	)
	(segment
		(start 339.366606 -63.056262)
		(end 339.463126 -62.959742)
		(width 0.0889)
		(layer "F.Cu")
		(net "CLK_25M_PCH_CPU0_DP")
	)
	(segment
		(start 339.399626 -69.136514)
		(end 339.524086 -69.012054)
		(width 0.13208)
		(layer "F.Cu")
		(net "CLK_25M_PCH_CPU0_DP")
	)
	(segment
		(start 338.393024 -72.15124)
		(end 338.569046 -72.15124)
		(width 0.13208)
		(layer "F.Cu")
		(net "CLK_25M_PCH_CPU0_DP")
	)
	(segment
		(start 339.399626 -67.114674)
		(end 339.399626 -67.090036)
		(width 0.0889)
		(layer "F.Cu")
		(net "CLK_25M_PCH_CPU0_DP")
	)
	(segment
		(start 339.524086 -69.012054)
		(end 339.524086 -68.631054)
		(width 0.13208)
		(layer "F.Cu")
		(net "CLK_25M_PCH_CPU0_DP")
	)
	(segment
		(start 339.399626 -68.506594)
		(end 339.399626 -68.125594)
		(width 0.13208)
		(layer "F.Cu")
		(net "CLK_25M_PCH_CPU0_DP")
	)
	(segment
		(start 339.399626 -69.517514)
		(end 339.399626 -69.136514)
		(width 0.13208)
		(layer "F.Cu")
		(net "CLK_25M_PCH_CPU0_DP")
	)
	(segment
		(start 339.366606 -61.207142)
		(end 339.366606 -60.953142)
		(width 0.0889)
		(layer "F.Cu")
		(net "CLK_25M_PCH_CPU0_DP")
	)
	(segment
		(start 337.23326 -74.311256)
		(end 337.23326 -73.311004)
		(width 0.13208)
		(layer "F.Cu")
		(net "CLK_25M_PCH_CPU0_DP")
	)
	(segment
		(start 339.463126 -63.660782)
		(end 339.463126 -63.406782)
		(width 0.0889)
		(layer "F.Cu")
		(net "CLK_25M_PCH_CPU0_DP")
	)
	(segment
		(start 339.463126 -60.856622)
		(end 339.463126 -60.602622)
		(width 0.0889)
		(layer "F.Cu")
		(net "CLK_25M_PCH_CPU0_DP")
	)
	(segment
		(start 339.463126 -60.602622)
		(end 339.366606 -60.506102)
		(width 0.0889)
		(layer "F.Cu")
		(net "CLK_25M_PCH_CPU0_DP")
	)
	(segment
		(start 339.366606 -62.355222)
		(end 339.463126 -62.258702)
		(width 0.0889)
		(layer "F.Cu")
		(net "CLK_25M_PCH_CPU0_DP")
	)
	(segment
		(start 338.055712 -72.488552)
		(end 338.393024 -72.15124)
		(width 0.13208)
		(layer "F.Cu")
		(net "CLK_25M_PCH_CPU0_DP")
	)
	(segment
		(start 339.366606 -61.654182)
		(end 339.463126 -61.557662)
		(width 0.0889)
		(layer "F.Cu")
		(net "CLK_25M_PCH_CPU0_DP")
	)
	(segment
		(start 339.463126 -62.258702)
		(end 339.463126 -62.004702)
		(width 0.0889)
		(layer "F.Cu")
		(net "CLK_25M_PCH_CPU0_DP")
	)
	(segment
		(start 339.524086 -69.641974)
		(end 339.399626 -69.517514)
		(width 0.13208)
		(layer "F.Cu")
		(net "CLK_25M_PCH_CPU0_DP")
	)
	(segment
		(start 339.524086 -67.620134)
		(end 339.399626 -67.495674)
		(width 0.13208)
		(layer "F.Cu")
		(net "CLK_25M_PCH_CPU0_DP")
	)
	(segment
		(start 338.055712 -72.664574)
		(end 338.055712 -72.488552)
		(width 0.13208)
		(layer "F.Cu")
		(net "CLK_25M_PCH_CPU0_DP")
	)
	(segment
		(start 339.399626 -70.147434)
		(end 339.524086 -70.022974)
		(width 0.13208)
		(layer "F.Cu")
		(net "CLK_25M_PCH_CPU0_DP")
	)
	(segment
		(start 339.366606 -67.057016)
		(end 339.366606 -63.757302)
		(width 0.0889)
		(layer "F.Cu")
		(net "CLK_25M_PCH_CPU0_DP")
	)
	(segment
		(start 339.366606 -60.506102)
		(end 339.366606 -60.212478)
		(width 0.0889)
		(layer "F.Cu")
		(net "CLK_25M_PCH_CPU0_DP")
	)
	(segment
		(start 339.463126 -62.959742)
		(end 339.463126 -62.705742)
		(width 0.0889)
		(layer "F.Cu")
		(net "CLK_25M_PCH_CPU0_DP")
	)
	(segment
		(start 337.603084 -72.94118)
		(end 337.779106 -72.94118)
		(width 0.13208)
		(layer "F.Cu")
		(net "CLK_25M_PCH_CPU0_DP")
	)
	(segment
		(start 339.400642 -60.129928)
		(end 339.400642 -59.098688)
		(width 0.0889)
		(layer "F.Cu")
		(net "CLK_25M_PCH_CPU0_DP")
	)
	(segment
		(start 339.463126 -61.303662)
		(end 339.366606 -61.207142)
		(width 0.0889)
		(layer "F.Cu")
		(net "CLK_25M_PCH_CPU0_DP")
	)
	(segment
		(start 339.366606 -60.953142)
		(end 339.463126 -60.856622)
		(width 0.0889)
		(layer "F.Cu")
		(net "CLK_25M_PCH_CPU0_DP")
	)
	(segment
		(start 339.224874 -71.319644)
		(end 339.399626 -70.896226)
		(width 0.13208)
		(layer "F.Cu")
		(net "CLK_25M_PCH_CPU0_DP")
	)
	(segment
		(start 339.399626 -68.125594)
		(end 339.524086 -68.001134)
		(width 0.13208)
		(layer "F.Cu")
		(net "CLK_25M_PCH_CPU0_DP")
	)
	(segment
		(start 339.366606 -62.609222)
		(end 339.366606 -62.355222)
		(width 0.0889)
		(layer "F.Cu")
		(net "CLK_25M_PCH_CPU0_DP")
	)
	(segment
		(start 339.399626 -70.896226)
		(end 339.399626 -70.147434)
		(width 0.13208)
		(layer "F.Cu")
		(net "CLK_25M_PCH_CPU0_DP")
	)
	(segment
		(start 339.399626 -67.090036)
		(end 339.366606 -67.057016)
		(width 0.0889)
		(layer "F.Cu")
		(net "CLK_25M_PCH_CPU0_DP")
	)
	(segment
		(start 339.524086 -68.631054)
		(end 339.399626 -68.506594)
		(width 0.13208)
		(layer "F.Cu")
		(net "CLK_25M_PCH_CPU0_DP")
	)
	(segment
		(start 338.569046 -72.15124)
		(end 338.845652 -71.874634)
		(width 0.13208)
		(layer "F.Cu")
		(net "CLK_25M_PCH_CPU0_DP")
	)
	(segment
		(start 337.23326 -73.311004)
		(end 337.603084 -72.94118)
		(width 0.13208)
		(layer "F.Cu")
		(net "CLK_25M_PCH_CPU0_DP")
	)
	(segment
		(start 339.400896 -59.098434)
		(end 339.400896 -58.850276)
		(width 0.0889)
		(layer "F.Cu")
		(net "CLK_25M_PCH_CPU0_DP")
	)
	(segment
		(start 339.524086 -70.022974)
		(end 339.524086 -69.641974)
		(width 0.13208)
		(layer "F.Cu")
		(net "CLK_25M_PCH_CPU0_DP")
	)
	(segment
		(start 339.400642 -59.098688)
		(end 339.400896 -59.098434)
		(width 0.0889)
		(layer "F.Cu")
		(net "CLK_25M_PCH_CPU0_DP")
	)
	(segment
		(start 339.366606 -63.757302)
		(end 339.463126 -63.660782)
		(width 0.0889)
		(layer "F.Cu")
		(net "CLK_25M_PCH_CPU0_DP")
	)
	(segment
		(start 339.463126 -62.004702)
		(end 339.366606 -61.908182)
		(width 0.0889)
		(layer "F.Cu")
		(net "CLK_25M_PCH_CPU0_DP")
	)
	(segment
		(start 339.463126 -61.557662)
		(end 339.463126 -61.303662)
		(width 0.0889)
		(layer "F.Cu")
		(net "CLK_25M_PCH_CPU0_DP")
	)
	(segment
		(start 337.485228 -74.563224)
		(end 337.23326 -74.311256)
		(width 0.13208)
		(layer "F.Cu")
		(net "CLK_25M_PCH_CPU0_DP")
	)
	(segment
		(start 338.845652 -71.874634)
		(end 338.845652 -71.698866)
		(width 0.13208)
		(layer "F.Cu")
		(net "CLK_25M_PCH_CPU0_DP")
	)
	(via
		(at 337.518756 -74.563224)
		(size 0.508)
		(drill 0.254)
		(layers "F.Cu" "B.Cu")
		(net "CLK_25M_PCH_CPU0_DP")
	)
	(via
		(at 340.46668 -137.622788)
		(size 0.508)
		(drill 0.254)
		(layers "F.Cu" "B.Cu")
		(net "CLK_25M_PCH_CPU0_DP")
	)
	(segment
		(start 339.30209 -137.832338)
		(end 338.841842 -137.832338)
		(width 0.13208)
		(layer "B.Cu")
		(net "CLK_25M_PCH_CPU0_DP")
	)
	(segment
		(start 339.81136 -137.323068)
		(end 339.30209 -137.832338)
		(width 0.13208)
		(layer "B.Cu")
		(net "CLK_25M_PCH_CPU0_DP")
	)
	(segment
		(start 340.16696 -137.323068)
		(end 339.81136 -137.323068)
		(width 0.13208)
		(layer "B.Cu")
		(net "CLK_25M_PCH_CPU0_DP")
	)
	(segment
		(start 340.46668 -137.622788)
		(end 340.16696 -137.323068)
		(width 0.13208)
		(layer "B.Cu")
		(net "CLK_25M_PCH_CPU0_DP")
	)
	(segment
		(start 340.46668 -137.622788)
		(end 340.76132 -137.328148)
		(width 0.14732)
		(layer "In2.Cu")
		(net "CLK_25M_PCH_CPU0_DP")
	)
	(segment
		(start 337.224116 -74.857864)
		(end 337.518756 -74.563224)
		(width 0.14732)
		(layer "In2.Cu")
		(net "CLK_25M_PCH_CPU0_DP")
	)
	(segment
		(start 341.67318 -130.800094)
		(end 336.52968 -104.941624)
		(width 0.14732)
		(layer "In2.Cu")
		(net "CLK_25M_PCH_CPU0_DP")
	)
	(segment
		(start 341.67318 -136.738614)
		(end 341.67318 -130.800094)
		(width 0.14732)
		(layer "In2.Cu")
		(net "CLK_25M_PCH_CPU0_DP")
	)
	(segment
		(start 340.76132 -137.328148)
		(end 341.083646 -137.328148)
		(width 0.14732)
		(layer "In2.Cu")
		(net "CLK_25M_PCH_CPU0_DP")
	)
	(segment
		(start 338.76488 -80.945482)
		(end 337.224116 -77.225652)
		(width 0.14732)
		(layer "In2.Cu")
		(net "CLK_25M_PCH_CPU0_DP")
	)
	(segment
		(start 336.52968 -104.941624)
		(end 336.52968 -86.3727)
		(width 0.14732)
		(layer "In2.Cu")
		(net "CLK_25M_PCH_CPU0_DP")
	)
	(segment
		(start 338.569046 -83.114642)
		(end 338.76488 -82.641694)
		(width 0.14732)
		(layer "In2.Cu")
		(net "CLK_25M_PCH_CPU0_DP")
	)
	(segment
		(start 336.52968 -86.3727)
		(end 337.391502 -84.292186)
		(width 0.14732)
		(layer "In2.Cu")
		(net "CLK_25M_PCH_CPU0_DP")
	)
	(segment
		(start 337.391502 -84.292186)
		(end 338.569046 -83.114642)
		(width 0.14732)
		(layer "In2.Cu")
		(net "CLK_25M_PCH_CPU0_DP")
	)
	(segment
		(start 341.083646 -137.328148)
		(end 341.67318 -136.738614)
		(width 0.14732)
		(layer "In2.Cu")
		(net "CLK_25M_PCH_CPU0_DP")
	)
	(segment
		(start 338.76488 -82.641694)
		(end 338.76488 -80.945482)
		(width 0.14732)
		(layer "In2.Cu")
		(net "CLK_25M_PCH_CPU0_DP")
	)
	(segment
		(start 337.224116 -77.225652)
		(end 337.224116 -74.857864)
		(width 0.14732)
		(layer "In2.Cu")
		(net "CLK_25M_PCH_CPU0_DP")
	)
	(segment
		(start 339.140546 -70.844664)
		(end 339.140546 -67.114674)
		(width 0.13208)
		(layer "F.Cu")
		(net "CLK_25M_PCH_CPU0_DN")
	)
	(segment
		(start 339.210396 -60.092082)
		(end 339.210396 -59.098688)
		(width 0.0889)
		(layer "F.Cu")
		(net "CLK_25M_PCH_CPU0_DN")
	)
	(segment
		(start 336.655156 -74.563224)
		(end 336.97418 -74.2442)
		(width 0.13208)
		(layer "F.Cu")
		(net "CLK_25M_PCH_CPU0_DN")
	)
	(segment
		(start 339.3059 -58.355992)
		(end 339.400896 -58.020204)
		(width 0.0889)
		(layer "F.Cu")
		(net "CLK_25M_PCH_CPU0_DN")
	)
	(segment
		(start 339.092794 -58.703972)
		(end 339.3059 -58.355992)
		(width 0.0889)
		(layer "F.Cu")
		(net "CLK_25M_PCH_CPU0_DN")
	)
	(segment
		(start 339.00491 -71.172832)
		(end 339.140546 -70.844664)
		(width 0.13208)
		(layer "F.Cu")
		(net "CLK_25M_PCH_CPU0_DN")
	)
	(segment
		(start 339.092794 -58.981086)
		(end 339.092794 -58.703972)
		(width 0.0889)
		(layer "F.Cu")
		(net "CLK_25M_PCH_CPU0_DN")
	)
	(segment
		(start 339.140546 -67.092576)
		(end 339.17636 -67.056762)
		(width 0.0889)
		(layer "F.Cu")
		(net "CLK_25M_PCH_CPU0_DN")
	)
	(segment
		(start 336.97418 -74.2442)
		(end 336.97418 -73.203562)
		(width 0.13208)
		(layer "F.Cu")
		(net "CLK_25M_PCH_CPU0_DN")
	)
	(segment
		(start 339.140546 -67.114674)
		(end 339.140546 -67.092576)
		(width 0.0889)
		(layer "F.Cu")
		(net "CLK_25M_PCH_CPU0_DN")
	)
	(segment
		(start 339.17636 -67.056762)
		(end 339.17636 -60.174378)
		(width 0.0889)
		(layer "F.Cu")
		(net "CLK_25M_PCH_CPU0_DN")
	)
	(segment
		(start 339.210396 -59.098688)
		(end 339.092794 -58.981086)
		(width 0.0889)
		(layer "F.Cu")
		(net "CLK_25M_PCH_CPU0_DN")
	)
	(segment
		(start 339.17636 -60.174378)
		(end 339.210396 -60.092082)
		(width 0.0889)
		(layer "F.Cu")
		(net "CLK_25M_PCH_CPU0_DN")
	)
	(segment
		(start 336.97418 -73.203562)
		(end 339.00491 -71.172832)
		(width 0.13208)
		(layer "F.Cu")
		(net "CLK_25M_PCH_CPU0_DN")
	)
	(via
		(at 340.46668 -136.759188)
		(size 0.508)
		(drill 0.254)
		(layers "F.Cu" "B.Cu")
		(net "CLK_25M_PCH_CPU0_DN")
	)
	(via
		(at 336.655156 -74.563224)
		(size 0.508)
		(drill 0.254)
		(layers "F.Cu" "B.Cu")
		(net "CLK_25M_PCH_CPU0_DN")
	)
	(segment
		(start 339.231986 -136.479534)
		(end 338.822284 -136.479534)
		(width 0.13208)
		(layer "B.Cu")
		(net "CLK_25M_PCH_CPU0_DN")
	)
	(segment
		(start 339.81644 -137.063988)
		(end 339.231986 -136.479534)
		(width 0.13208)
		(layer "B.Cu")
		(net "CLK_25M_PCH_CPU0_DN")
	)
	(segment
		(start 340.16188 -137.063988)
		(end 339.81644 -137.063988)
		(width 0.13208)
		(layer "B.Cu")
		(net "CLK_25M_PCH_CPU0_DN")
	)
	(segment
		(start 340.46668 -136.759188)
		(end 340.16188 -137.063988)
		(width 0.13208)
		(layer "B.Cu")
		(net "CLK_25M_PCH_CPU0_DN")
	)
	(segment
		(start 336.25536 -104.968802)
		(end 336.25536 -86.31809)
		(width 0.14732)
		(layer "In2.Cu")
		(net "CLK_25M_PCH_CPU0_DN")
	)
	(segment
		(start 341.39886 -136.624822)
		(end 341.39886 -136.028938)
		(width 0.14732)
		(layer "In2.Cu")
		(net "CLK_25M_PCH_CPU0_DN")
	)
	(segment
		(start 340.46668 -136.759188)
		(end 340.76132 -137.053828)
		(width 0.14732)
		(layer "In2.Cu")
		(net "CLK_25M_PCH_CPU0_DN")
	)
	(segment
		(start 341.39886 -134.365238)
		(end 341.39886 -133.996938)
		(width 0.14732)
		(layer "In2.Cu")
		(net "CLK_25M_PCH_CPU0_DN")
	)
	(segment
		(start 338.49056 -82.587084)
		(end 338.49056 -81.000092)
		(width 0.14732)
		(layer "In2.Cu")
		(net "CLK_25M_PCH_CPU0_DN")
	)
	(segment
		(start 336.25536 -86.31809)
		(end 337.158838 -84.136738)
		(width 0.14732)
		(layer "In2.Cu")
		(net "CLK_25M_PCH_CPU0_DN")
	)
	(segment
		(start 341.39886 -135.012938)
		(end 341.25916 -134.873238)
		(width 0.14732)
		(layer "In2.Cu")
		(net "CLK_25M_PCH_CPU0_DN")
	)
	(segment
		(start 340.76132 -137.053828)
		(end 340.969854 -137.053828)
		(width 0.14732)
		(layer "In2.Cu")
		(net "CLK_25M_PCH_CPU0_DN")
	)
	(segment
		(start 341.39886 -132.980938)
		(end 341.25916 -132.841238)
		(width 0.14732)
		(layer "In2.Cu")
		(net "CLK_25M_PCH_CPU0_DN")
	)
	(segment
		(start 336.949796 -74.857864)
		(end 336.655156 -74.563224)
		(width 0.14732)
		(layer "In2.Cu")
		(net "CLK_25M_PCH_CPU0_DN")
	)
	(segment
		(start 341.25916 -135.520938)
		(end 341.39886 -135.381238)
		(width 0.14732)
		(layer "In2.Cu")
		(net "CLK_25M_PCH_CPU0_DN")
	)
	(segment
		(start 341.25916 -134.873238)
		(end 341.25916 -134.504938)
		(width 0.14732)
		(layer "In2.Cu")
		(net "CLK_25M_PCH_CPU0_DN")
	)
	(segment
		(start 341.39886 -136.028938)
		(end 341.25916 -135.889238)
		(width 0.14732)
		(layer "In2.Cu")
		(net "CLK_25M_PCH_CPU0_DN")
	)
	(segment
		(start 341.25916 -134.504938)
		(end 341.39886 -134.365238)
		(width 0.14732)
		(layer "In2.Cu")
		(net "CLK_25M_PCH_CPU0_DN")
	)
	(segment
		(start 341.25916 -133.857238)
		(end 341.25916 -133.488938)
		(width 0.14732)
		(layer "In2.Cu")
		(net "CLK_25M_PCH_CPU0_DN")
	)
	(segment
		(start 341.39886 -133.996938)
		(end 341.25916 -133.857238)
		(width 0.14732)
		(layer "In2.Cu")
		(net "CLK_25M_PCH_CPU0_DN")
	)
	(segment
		(start 341.25916 -132.472938)
		(end 341.39886 -132.333238)
		(width 0.14732)
		(layer "In2.Cu")
		(net "CLK_25M_PCH_CPU0_DN")
	)
	(segment
		(start 338.336382 -82.959194)
		(end 338.49056 -82.587084)
		(width 0.14732)
		(layer "In2.Cu")
		(net "CLK_25M_PCH_CPU0_DN")
	)
	(segment
		(start 336.949796 -77.280262)
		(end 336.949796 -74.857864)
		(width 0.14732)
		(layer "In2.Cu")
		(net "CLK_25M_PCH_CPU0_DN")
	)
	(segment
		(start 341.25916 -133.488938)
		(end 341.39886 -133.349238)
		(width 0.14732)
		(layer "In2.Cu")
		(net "CLK_25M_PCH_CPU0_DN")
	)
	(segment
		(start 341.25916 -135.889238)
		(end 341.25916 -135.520938)
		(width 0.14732)
		(layer "In2.Cu")
		(net "CLK_25M_PCH_CPU0_DN")
	)
	(segment
		(start 340.969854 -137.053828)
		(end 341.39886 -136.624822)
		(width 0.14732)
		(layer "In2.Cu")
		(net "CLK_25M_PCH_CPU0_DN")
	)
	(segment
		(start 341.25916 -132.841238)
		(end 341.25916 -132.472938)
		(width 0.14732)
		(layer "In2.Cu")
		(net "CLK_25M_PCH_CPU0_DN")
	)
	(segment
		(start 338.49056 -81.000092)
		(end 336.949796 -77.280262)
		(width 0.14732)
		(layer "In2.Cu")
		(net "CLK_25M_PCH_CPU0_DN")
	)
	(segment
		(start 341.39886 -135.381238)
		(end 341.39886 -135.012938)
		(width 0.14732)
		(layer "In2.Cu")
		(net "CLK_25M_PCH_CPU0_DN")
	)
	(segment
		(start 341.39886 -132.333238)
		(end 341.39886 -130.827272)
		(width 0.14732)
		(layer "In2.Cu")
		(net "CLK_25M_PCH_CPU0_DN")
	)
	(segment
		(start 341.39886 -130.827272)
		(end 336.25536 -104.968802)
		(width 0.14732)
		(layer "In2.Cu")
		(net "CLK_25M_PCH_CPU0_DN")
	)
	(segment
		(start 337.158838 -84.136738)
		(end 338.336382 -82.959194)
		(width 0.14732)
		(layer "In2.Cu")
		(net "CLK_25M_PCH_CPU0_DN")
	)
	(segment
		(start 341.39886 -133.349238)
		(end 341.39886 -132.980938)
		(width 0.14732)
		(layer "In2.Cu")
		(net "CLK_25M_PCH_CPU0_DN")
	)
	(segment
		(start 186.55538 -111.775748)
		(end 187.2742 -111.775748)
		(width 0.12954)
		(layer "F.Cu")
		(net "CLK_25M_OSC_MAIN_FPGA")
	)
	(segment
		(start 186.155584 -112.175544)
		(end 186.55538 -111.775748)
		(width 0.12954)
		(layer "F.Cu")
		(net "CLK_25M_OSC_MAIN_FPGA")
	)
	(segment
		(start 192.480184 -112.906302)
		(end 192.155064 -112.906302)
		(width 0.12954)
		(layer "F.Cu")
		(net "CLK_25M_OSC_MAIN_FPGA")
	)
	(segment
		(start 191.89319 -112.644428)
		(end 188.97092 -112.644428)
		(width 0.12954)
		(layer "F.Cu")
		(net "CLK_25M_OSC_MAIN_FPGA")
	)
	(segment
		(start 187.2742 -111.775748)
		(end 188.14288 -112.644428)
		(width 0.12954)
		(layer "F.Cu")
		(net "CLK_25M_OSC_MAIN_FPGA")
	)
	(segment
		(start 192.58788 -113.013998)
		(end 192.480184 -112.906302)
		(width 0.12954)
		(layer "F.Cu")
		(net "CLK_25M_OSC_MAIN_FPGA")
	)
	(segment
		(start 188.14288 -112.644428)
		(end 188.97092 -112.644428)
		(width 0.12954)
		(layer "F.Cu")
		(net "CLK_25M_OSC_MAIN_FPGA")
	)
	(segment
		(start 192.155064 -112.906302)
		(end 191.89319 -112.644428)
		(width 0.12954)
		(layer "F.Cu")
		(net "CLK_25M_OSC_MAIN_FPGA")
	)
	(via
		(at 188.97092 -112.644428)
		(size 0.508)
		(drill 0.254)
		(layers "F.Cu" "B.Cu")
		(net "CLK_25M_OSC_MAIN_FPGA")
	)
	(segment
		(start 193.159126 -112.432338)
		(end 192.940686 -112.213898)
		(width 0.12954)
		(layer "F.Cu")
		(net "CLK_25M_OSC_FPGA_R")
	)
	(segment
		(start 193.627502 -111.963962)
		(end 193.159126 -112.432338)
		(width 0.12954)
		(layer "F.Cu")
		(net "CLK_25M_OSC_FPGA_R")
	)
	(segment
		(start 194.150996 -111.963962)
		(end 193.627502 -111.963962)
		(width 0.12954)
		(layer "F.Cu")
		(net "CLK_25M_OSC_FPGA_R")
	)
	(segment
		(start 192.940686 -112.213898)
		(end 192.58788 -112.213898)
		(width 0.12954)
		(layer "F.Cu")
		(net "CLK_25M_OSC_FPGA_R")
	)
	(via
		(at 193.159126 -112.432338)
		(size 0.508)
		(drill 0.254)
		(layers "F.Cu" "B.Cu")
		(net "CLK_25M_OSC_FPGA_R")
	)
	(segment
		(start 236.662468 -134.99846)
		(end 236.405674 -134.741666)
		(width 0.13208)
		(layer "F.Cu")
		(net "CLK_25M_NSSC_CPU1_DP")
	)
	(segment
		(start 121.977912 -239.57534)
		(end 121.978166 -239.575086)
		(width 0.13208)
		(layer "F.Cu")
		(net "CLK_25M_NSSC_CPU1_DP")
	)
	(segment
		(start 186.18708 -153.533602)
		(end 186.18708 -151.336248)
		(width 0.13208)
		(layer "F.Cu")
		(net "CLK_25M_NSSC_CPU1_DP")
	)
	(segment
		(start 236.662468 -135.841994)
		(end 236.662468 -134.99846)
		(width 0.13208)
		(layer "F.Cu")
		(net "CLK_25M_NSSC_CPU1_DP")
	)
	(segment
		(start 121.978166 -239.575086)
		(end 121.978166 -239.0394)
		(width 0.13208)
		(layer "F.Cu")
		(net "CLK_25M_NSSC_CPU1_DP")
	)
	(segment
		(start 206.470504 -140.602208)
		(end 236.076236 -136.210548)
		(width 0.13208)
		(layer "F.Cu")
		(net "CLK_25M_NSSC_CPU1_DP")
	)
	(segment
		(start 236.51464 -135.989568)
		(end 236.662468 -135.841994)
		(width 0.13208)
		(layer "F.Cu")
		(net "CLK_25M_NSSC_CPU1_DP")
	)
	(segment
		(start 186.590686 -153.937208)
		(end 186.18708 -153.533602)
		(width 0.13208)
		(layer "F.Cu")
		(net "CLK_25M_NSSC_CPU1_DP")
	)
	(segment
		(start 190.168022 -147.355306)
		(end 206.470504 -140.602208)
		(width 0.13208)
		(layer "F.Cu")
		(net "CLK_25M_NSSC_CPU1_DP")
	)
	(segment
		(start 186.82208 -153.937208)
		(end 186.590686 -153.937208)
		(width 0.13208)
		(layer "F.Cu")
		(net "CLK_25M_NSSC_CPU1_DP")
	)
	(segment
		(start 236.076236 -136.210548)
		(end 236.51464 -135.989568)
		(width 0.13208)
		(layer "F.Cu")
		(net "CLK_25M_NSSC_CPU1_DP")
	)
	(segment
		(start 186.18708 -151.336248)
		(end 190.168022 -147.355306)
		(width 0.13208)
		(layer "F.Cu")
		(net "CLK_25M_NSSC_CPU1_DP")
	)
	(segment
		(start 187.12434 -154.239468)
		(end 186.82208 -153.937208)
		(width 0.13208)
		(layer "F.Cu")
		(net "CLK_25M_NSSC_CPU1_DP")
	)
	(via
		(at 121.978166 -239.0394)
		(size 0.4572)
		(drill 0.2032)
		(layers "F.Cu" "B.Cu")
		(net "CLK_25M_NSSC_CPU1_DP")
	)
	(via
		(at 187.12434 -154.239468)
		(size 0.508)
		(drill 0.254)
		(layers "F.Cu" "B.Cu")
		(net "CLK_25M_NSSC_CPU1_DP")
	)
	(via
		(at 236.405674 -134.741666)
		(size 0.508)
		(drill 0.254)
		(layers "F.Cu" "B.Cu")
		(net "CLK_25M_NSSC_CPU1_DP")
	)
	(segment
		(start 121.842784 -238.690404)
		(end 121.821702 -238.768382)
		(width 0.0889)
		(layer "B.Cu")
		(net "CLK_25M_NSSC_CPU1_DP")
	)
	(segment
		(start 124.044456 -238.714534)
		(end 124.032518 -238.707422)
		(width 0.0889)
		(layer "B.Cu")
		(net "CLK_25M_NSSC_CPU1_DP")
	)
	(segment
		(start 124.984256 -238.714534)
		(end 124.972318 -238.707422)
		(width 0.0889)
		(layer "B.Cu")
		(net "CLK_25M_NSSC_CPU1_DP")
	)
	(segment
		(start 122.164856 -238.714534)
		(end 122.152918 -238.707422)
		(width 0.0889)
		(layer "B.Cu")
		(net "CLK_25M_NSSC_CPU1_DP")
	)
	(segment
		(start 132.50291 -238.714534)
		(end 132.494528 -238.709454)
		(width 0.0889)
		(layer "B.Cu")
		(net "CLK_25M_NSSC_CPU1_DP")
	)
	(segment
		(start 137.68832 -238.698786)
		(end 137.653776 -238.664242)
		(width 0.0889)
		(layer "B.Cu")
		(net "CLK_25M_NSSC_CPU1_DP")
	)
	(segment
		(start 125.92431 -238.714534)
		(end 125.915928 -238.709454)
		(width 0.0889)
		(layer "B.Cu")
		(net "CLK_25M_NSSC_CPU1_DP")
	)
	(segment
		(start 162.202622 -236.330998)
		(end 162.170872 -236.330998)
		(width 0.13208)
		(layer "B.Cu")
		(net "CLK_25M_NSSC_CPU1_DP")
	)
	(segment
		(start 180.68544 -159.532066)
		(end 173.282864 -170.61053)
		(width 0.13208)
		(layer "B.Cu")
		(net "CLK_25M_NSSC_CPU1_DP")
	)
	(segment
		(start 128.743456 -238.714534)
		(end 128.731518 -238.707422)
		(width 0.0889)
		(layer "B.Cu")
		(net "CLK_25M_NSSC_CPU1_DP")
	)
	(segment
		(start 183.733694 -156.674312)
		(end 183.543194 -156.674312)
		(width 0.13208)
		(layer "B.Cu")
		(net "CLK_25M_NSSC_CPU1_DP")
	)
	(segment
		(start 186.285378 -153.932128)
		(end 183.988964 -156.228542)
		(width 0.13208)
		(layer "B.Cu")
		(net "CLK_25M_NSSC_CPU1_DP")
	)
	(segment
		(start 149.352 -238.698786)
		(end 137.710418 -238.698786)
		(width 0.13208)
		(layer "B.Cu")
		(net "CLK_25M_NSSC_CPU1_DP")
	)
	(segment
		(start 164.253418 -199.52208)
		(end 163.41852 -200.356724)
		(width 0.13208)
		(layer "B.Cu")
		(net "CLK_25M_NSSC_CPU1_DP")
	)
	(segment
		(start 187.12434 -154.239468)
		(end 186.817 -153.932128)
		(width 0.13208)
		(layer "B.Cu")
		(net "CLK_25M_NSSC_CPU1_DP")
	)
	(segment
		(start 186.817 -153.932128)
		(end 186.285378 -153.932128)
		(width 0.13208)
		(layer "B.Cu")
		(net "CLK_25M_NSSC_CPU1_DP")
	)
	(segment
		(start 130.623056 -238.714534)
		(end 130.611118 -238.707422)
		(width 0.0889)
		(layer "B.Cu")
		(net "CLK_25M_NSSC_CPU1_DP")
	)
	(segment
		(start 126.863856 -238.714534)
		(end 126.855474 -238.709454)
		(width 0.0889)
		(layer "B.Cu")
		(net "CLK_25M_NSSC_CPU1_DP")
	)
	(segment
		(start 183.543194 -156.674312)
		(end 180.68544 -159.532066)
		(width 0.13208)
		(layer "B.Cu")
		(net "CLK_25M_NSSC_CPU1_DP")
	)
	(segment
		(start 236.7534 -134.452868)
		(end 236.7534 -134.21995)
		(width 0.13208)
		(layer "B.Cu")
		(net "CLK_25M_NSSC_CPU1_DP")
	)
	(segment
		(start 164.72916 -191.26073)
		(end 164.72916 -198.373238)
		(width 0.13208)
		(layer "B.Cu")
		(net "CLK_25M_NSSC_CPU1_DP")
	)
	(segment
		(start 164.72916 -198.373238)
		(end 164.253418 -199.52208)
		(width 0.13208)
		(layer "B.Cu")
		(net "CLK_25M_NSSC_CPU1_DP")
	)
	(segment
		(start 183.988964 -156.228542)
		(end 183.988964 -156.419042)
		(width 0.13208)
		(layer "B.Cu")
		(net "CLK_25M_NSSC_CPU1_DP")
	)
	(segment
		(start 137.710418 -238.698786)
		(end 137.68832 -238.698786)
		(width 0.0889)
		(layer "B.Cu")
		(net "CLK_25M_NSSC_CPU1_DP")
	)
	(segment
		(start 159.79267 -237.31601)
		(end 152.690322 -237.31601)
		(width 0.13208)
		(layer "B.Cu")
		(net "CLK_25M_NSSC_CPU1_DP")
	)
	(segment
		(start 137.653776 -238.664242)
		(end 137.014712 -238.664242)
		(width 0.0889)
		(layer "B.Cu")
		(net "CLK_25M_NSSC_CPU1_DP")
	)
	(segment
		(start 152.690322 -237.31601)
		(end 149.352 -238.698786)
		(width 0.13208)
		(layer "B.Cu")
		(net "CLK_25M_NSSC_CPU1_DP")
	)
	(segment
		(start 121.821702 -238.768382)
		(end 121.978166 -239.0394)
		(width 0.0889)
		(layer "B.Cu")
		(net "CLK_25M_NSSC_CPU1_DP")
	)
	(segment
		(start 121.84253 -238.689896)
		(end 121.842784 -238.690404)
		(width 0.0889)
		(layer "B.Cu")
		(net "CLK_25M_NSSC_CPU1_DP")
	)
	(segment
		(start 236.7534 -134.21995)
		(end 236.582204 -134.048754)
		(width 0.13208)
		(layer "B.Cu")
		(net "CLK_25M_NSSC_CPU1_DP")
	)
	(segment
		(start 131.562856 -238.714534)
		(end 131.550918 -238.707422)
		(width 0.0889)
		(layer "B.Cu")
		(net "CLK_25M_NSSC_CPU1_DP")
	)
	(segment
		(start 236.405674 -134.741666)
		(end 236.464602 -134.741666)
		(width 0.13208)
		(layer "B.Cu")
		(net "CLK_25M_NSSC_CPU1_DP")
	)
	(segment
		(start 163.41852 -200.356724)
		(end 163.41852 -235.114846)
		(width 0.13208)
		(layer "B.Cu")
		(net "CLK_25M_NSSC_CPU1_DP")
	)
	(segment
		(start 127.803656 -238.714534)
		(end 127.791718 -238.707422)
		(width 0.0889)
		(layer "B.Cu")
		(net "CLK_25M_NSSC_CPU1_DP")
	)
	(segment
		(start 236.464602 -134.741666)
		(end 236.7534 -134.452868)
		(width 0.13208)
		(layer "B.Cu")
		(net "CLK_25M_NSSC_CPU1_DP")
	)
	(segment
		(start 173.282864 -170.61053)
		(end 164.72916 -191.26073)
		(width 0.13208)
		(layer "B.Cu")
		(net "CLK_25M_NSSC_CPU1_DP")
	)
	(segment
		(start 163.41852 -235.114846)
		(end 162.202622 -236.330998)
		(width 0.13208)
		(layer "B.Cu")
		(net "CLK_25M_NSSC_CPU1_DP")
	)
	(segment
		(start 183.988964 -156.419042)
		(end 183.733694 -156.674312)
		(width 0.13208)
		(layer "B.Cu")
		(net "CLK_25M_NSSC_CPU1_DP")
	)
	(segment
		(start 162.170872 -236.330998)
		(end 159.79267 -237.31601)
		(width 0.13208)
		(layer "B.Cu")
		(net "CLK_25M_NSSC_CPU1_DP")
	)
	(arc
		(start 123.105164 -238.714788)
		(mid 122.917712 -238.664552)
		(end 122.73026 -238.714788)
		(width 0.0889)
		(layer "B.Cu")
		(net "CLK_25M_NSSC_CPU1_DP")
	)
	(arc
		(start 134.947914 -238.714788)
		(mid 134.665466 -238.790471)
		(end 134.383018 -238.714788)
		(width 0.0889)
		(layer "B.Cu")
		(net "CLK_25M_NSSC_CPU1_DP")
	)
	(arc
		(start 127.791718 -238.707422)
		(mid 127.609548 -238.664433)
		(end 127.42926 -238.714788)
		(width 0.0889)
		(layer "B.Cu")
		(net "CLK_25M_NSSC_CPU1_DP")
	)
	(arc
		(start 124.60986 -238.714788)
		(mid 124.327129 -238.790471)
		(end 124.044456 -238.714534)
		(width 0.0889)
		(layer "B.Cu")
		(net "CLK_25M_NSSC_CPU1_DP")
	)
	(arc
		(start 130.611118 -238.707422)
		(mid 130.428948 -238.664433)
		(end 130.24866 -238.714788)
		(width 0.0889)
		(layer "B.Cu")
		(net "CLK_25M_NSSC_CPU1_DP")
	)
	(arc
		(start 125.54966 -238.714788)
		(mid 125.266929 -238.790471)
		(end 124.984256 -238.714534)
		(width 0.0889)
		(layer "B.Cu")
		(net "CLK_25M_NSSC_CPU1_DP")
	)
	(arc
		(start 135.887714 -238.714788)
		(mid 135.605266 -238.790471)
		(end 135.322818 -238.714788)
		(width 0.0889)
		(layer "B.Cu")
		(net "CLK_25M_NSSC_CPU1_DP")
	)
	(arc
		(start 125.915928 -238.709454)
		(mid 125.732107 -238.664396)
		(end 125.54966 -238.714788)
		(width 0.0889)
		(layer "B.Cu")
		(net "CLK_25M_NSSC_CPU1_DP")
	)
	(arc
		(start 128.731518 -238.707422)
		(mid 128.549348 -238.664433)
		(end 128.36906 -238.714788)
		(width 0.0889)
		(layer "B.Cu")
		(net "CLK_25M_NSSC_CPU1_DP")
	)
	(arc
		(start 131.550918 -238.707422)
		(mid 131.368748 -238.664433)
		(end 131.18846 -238.714788)
		(width 0.0889)
		(layer "B.Cu")
		(net "CLK_25M_NSSC_CPU1_DP")
	)
	(arc
		(start 136.982454 -238.665766)
		(mid 136.9023 -238.681791)
		(end 136.827514 -238.714788)
		(width 0.0889)
		(layer "B.Cu")
		(net "CLK_25M_NSSC_CPU1_DP")
	)
	(arc
		(start 136.827514 -238.714788)
		(mid 136.545066 -238.790471)
		(end 136.262618 -238.714788)
		(width 0.0889)
		(layer "B.Cu")
		(net "CLK_25M_NSSC_CPU1_DP")
	)
	(arc
		(start 129.683764 -238.714788)
		(mid 129.496312 -238.664552)
		(end 129.30886 -238.714788)
		(width 0.0889)
		(layer "B.Cu")
		(net "CLK_25M_NSSC_CPU1_DP")
	)
	(arc
		(start 135.322818 -238.714788)
		(mid 135.135366 -238.664552)
		(end 134.947914 -238.714788)
		(width 0.0889)
		(layer "B.Cu")
		(net "CLK_25M_NSSC_CPU1_DP")
	)
	(arc
		(start 132.12826 -238.714788)
		(mid 131.845529 -238.790471)
		(end 131.562856 -238.714534)
		(width 0.0889)
		(layer "B.Cu")
		(net "CLK_25M_NSSC_CPU1_DP")
	)
	(arc
		(start 128.36906 -238.714788)
		(mid 128.086329 -238.790471)
		(end 127.803656 -238.714534)
		(width 0.0889)
		(layer "B.Cu")
		(net "CLK_25M_NSSC_CPU1_DP")
	)
	(arc
		(start 133.068314 -238.714788)
		(mid 132.785583 -238.790471)
		(end 132.50291 -238.714534)
		(width 0.0889)
		(layer "B.Cu")
		(net "CLK_25M_NSSC_CPU1_DP")
	)
	(arc
		(start 133.443218 -238.714788)
		(mid 133.255766 -238.664552)
		(end 133.068314 -238.714788)
		(width 0.0889)
		(layer "B.Cu")
		(net "CLK_25M_NSSC_CPU1_DP")
	)
	(arc
		(start 124.972318 -238.707422)
		(mid 124.790148 -238.664433)
		(end 124.60986 -238.714788)
		(width 0.0889)
		(layer "B.Cu")
		(net "CLK_25M_NSSC_CPU1_DP")
	)
	(arc
		(start 126.489714 -238.714788)
		(mid 126.206983 -238.790471)
		(end 125.92431 -238.714534)
		(width 0.0889)
		(layer "B.Cu")
		(net "CLK_25M_NSSC_CPU1_DP")
	)
	(arc
		(start 124.032518 -238.707422)
		(mid 123.850348 -238.664433)
		(end 123.67006 -238.714788)
		(width 0.0889)
		(layer "B.Cu")
		(net "CLK_25M_NSSC_CPU1_DP")
	)
	(arc
		(start 129.30886 -238.714788)
		(mid 129.026129 -238.790471)
		(end 128.743456 -238.714534)
		(width 0.0889)
		(layer "B.Cu")
		(net "CLK_25M_NSSC_CPU1_DP")
	)
	(arc
		(start 127.42926 -238.714788)
		(mid 127.146529 -238.790471)
		(end 126.863856 -238.714534)
		(width 0.0889)
		(layer "B.Cu")
		(net "CLK_25M_NSSC_CPU1_DP")
	)
	(arc
		(start 132.494528 -238.709454)
		(mid 132.310707 -238.664396)
		(end 132.12826 -238.714788)
		(width 0.0889)
		(layer "B.Cu")
		(net "CLK_25M_NSSC_CPU1_DP")
	)
	(arc
		(start 134.008114 -238.714788)
		(mid 133.725666 -238.790471)
		(end 133.443218 -238.714788)
		(width 0.0889)
		(layer "B.Cu")
		(net "CLK_25M_NSSC_CPU1_DP")
	)
	(arc
		(start 131.18846 -238.714788)
		(mid 130.905729 -238.790471)
		(end 130.623056 -238.714534)
		(width 0.0889)
		(layer "B.Cu")
		(net "CLK_25M_NSSC_CPU1_DP")
	)
	(arc
		(start 137.014712 -238.664242)
		(mid 136.998567 -238.664656)
		(end 136.982454 -238.665766)
		(width 0.0889)
		(layer "B.Cu")
		(net "CLK_25M_NSSC_CPU1_DP")
	)
	(arc
		(start 122.152918 -238.707422)
		(mid 121.999621 -238.664954)
		(end 121.84253 -238.689896)
		(width 0.0889)
		(layer "B.Cu")
		(net "CLK_25M_NSSC_CPU1_DP")
	)
	(arc
		(start 123.67006 -238.714788)
		(mid 123.387612 -238.790471)
		(end 123.105164 -238.714788)
		(width 0.0889)
		(layer "B.Cu")
		(net "CLK_25M_NSSC_CPU1_DP")
	)
	(arc
		(start 130.24866 -238.714788)
		(mid 129.966212 -238.790471)
		(end 129.683764 -238.714788)
		(width 0.0889)
		(layer "B.Cu")
		(net "CLK_25M_NSSC_CPU1_DP")
	)
	(arc
		(start 134.383018 -238.714788)
		(mid 134.195566 -238.664552)
		(end 134.008114 -238.714788)
		(width 0.0889)
		(layer "B.Cu")
		(net "CLK_25M_NSSC_CPU1_DP")
	)
	(arc
		(start 136.262618 -238.714788)
		(mid 136.075166 -238.664552)
		(end 135.887714 -238.714788)
		(width 0.0889)
		(layer "B.Cu")
		(net "CLK_25M_NSSC_CPU1_DP")
	)
	(arc
		(start 122.73026 -238.714788)
		(mid 122.447529 -238.790471)
		(end 122.164856 -238.714534)
		(width 0.0889)
		(layer "B.Cu")
		(net "CLK_25M_NSSC_CPU1_DP")
	)
	(arc
		(start 126.855474 -238.709454)
		(mid 126.671907 -238.664517)
		(end 126.489714 -238.714788)
		(width 0.0889)
		(layer "B.Cu")
		(net "CLK_25M_NSSC_CPU1_DP")
	)
	(segment
		(start 236.921548 -135.949436)
		(end 236.668564 -136.20242)
		(width 0.13208)
		(layer "F.Cu")
		(net "CLK_25M_NSSC_CPU1_DN")
	)
	(segment
		(start 237.178342 -134.741666)
		(end 236.921548 -134.99846)
		(width 0.13208)
		(layer "F.Cu")
		(net "CLK_25M_NSSC_CPU1_DN")
	)
	(segment
		(start 187.611004 -150.278846)
		(end 187.341764 -150.548086)
		(width 0.13208)
		(layer "F.Cu")
		(net "CLK_25M_NSSC_CPU1_DN")
	)
	(segment
		(start 186.44616 -151.44369)
		(end 186.44616 -153.42616)
		(width 0.13208)
		(layer "F.Cu")
		(net "CLK_25M_NSSC_CPU1_DN")
	)
	(segment
		(start 236.921548 -134.99846)
		(end 236.921548 -135.949436)
		(width 0.13208)
		(layer "F.Cu")
		(net "CLK_25M_NSSC_CPU1_DN")
	)
	(segment
		(start 187.787026 -150.278846)
		(end 187.611004 -150.278846)
		(width 0.13208)
		(layer "F.Cu")
		(net "CLK_25M_NSSC_CPU1_DN")
	)
	(segment
		(start 189.175644 -148.714206)
		(end 188.771784 -149.118066)
		(width 0.13208)
		(layer "F.Cu")
		(net "CLK_25M_NSSC_CPU1_DN")
	)
	(segment
		(start 190.314834 -147.575016)
		(end 189.62116 -148.26869)
		(width 0.13208)
		(layer "F.Cu")
		(net "CLK_25M_NSSC_CPU1_DN")
	)
	(segment
		(start 188.326014 -149.563836)
		(end 188.056774 -149.833076)
		(width 0.13208)
		(layer "F.Cu")
		(net "CLK_25M_NSSC_CPU1_DN")
	)
	(segment
		(start 186.895994 -150.993856)
		(end 186.44616 -151.44369)
		(width 0.13208)
		(layer "F.Cu")
		(net "CLK_25M_NSSC_CPU1_DN")
	)
	(segment
		(start 206.5401 -140.853922)
		(end 190.314834 -147.575016)
		(width 0.13208)
		(layer "F.Cu")
		(net "CLK_25M_NSSC_CPU1_DN")
	)
	(segment
		(start 188.502036 -149.563836)
		(end 188.326014 -149.563836)
		(width 0.13208)
		(layer "F.Cu")
		(net "CLK_25M_NSSC_CPU1_DN")
	)
	(segment
		(start 186.82208 -153.678128)
		(end 187.12434 -153.375868)
		(width 0.13208)
		(layer "F.Cu")
		(net "CLK_25M_NSSC_CPU1_DN")
	)
	(segment
		(start 188.056774 -149.833076)
		(end 188.056774 -150.009098)
		(width 0.13208)
		(layer "F.Cu")
		(net "CLK_25M_NSSC_CPU1_DN")
	)
	(segment
		(start 189.351666 -148.714206)
		(end 189.175644 -148.714206)
		(width 0.13208)
		(layer "F.Cu")
		(net "CLK_25M_NSSC_CPU1_DN")
	)
	(segment
		(start 187.341764 -150.548086)
		(end 187.341764 -150.724108)
		(width 0.13208)
		(layer "F.Cu")
		(net "CLK_25M_NSSC_CPU1_DN")
	)
	(segment
		(start 189.62116 -148.444712)
		(end 189.351666 -148.714206)
		(width 0.13208)
		(layer "F.Cu")
		(net "CLK_25M_NSSC_CPU1_DN")
	)
	(segment
		(start 189.62116 -148.26869)
		(end 189.62116 -148.444712)
		(width 0.13208)
		(layer "F.Cu")
		(net "CLK_25M_NSSC_CPU1_DN")
	)
	(segment
		(start 188.056774 -150.009098)
		(end 187.787026 -150.278846)
		(width 0.13208)
		(layer "F.Cu")
		(net "CLK_25M_NSSC_CPU1_DN")
	)
	(segment
		(start 236.668564 -136.20242)
		(end 236.155484 -136.460738)
		(width 0.13208)
		(layer "F.Cu")
		(net "CLK_25M_NSSC_CPU1_DN")
	)
	(segment
		(start 186.698128 -153.678128)
		(end 186.82208 -153.678128)
		(width 0.13208)
		(layer "F.Cu")
		(net "CLK_25M_NSSC_CPU1_DN")
	)
	(segment
		(start 187.341764 -150.724108)
		(end 187.072016 -150.993856)
		(width 0.13208)
		(layer "F.Cu")
		(net "CLK_25M_NSSC_CPU1_DN")
	)
	(segment
		(start 121.508266 -238.761524)
		(end 121.508012 -238.76127)
		(width 0.13208)
		(layer "F.Cu")
		(net "CLK_25M_NSSC_CPU1_DN")
	)
	(segment
		(start 236.155484 -136.460738)
		(end 206.5401 -140.853922)
		(width 0.13208)
		(layer "F.Cu")
		(net "CLK_25M_NSSC_CPU1_DN")
	)
	(segment
		(start 121.508012 -238.76127)
		(end 121.508012 -238.225584)
		(width 0.13208)
		(layer "F.Cu")
		(net "CLK_25M_NSSC_CPU1_DN")
	)
	(segment
		(start 186.44616 -153.42616)
		(end 186.698128 -153.678128)
		(width 0.13208)
		(layer "F.Cu")
		(net "CLK_25M_NSSC_CPU1_DN")
	)
	(segment
		(start 188.771784 -149.294088)
		(end 188.502036 -149.563836)
		(width 0.13208)
		(layer "F.Cu")
		(net "CLK_25M_NSSC_CPU1_DN")
	)
	(segment
		(start 188.771784 -149.118066)
		(end 188.771784 -149.294088)
		(width 0.13208)
		(layer "F.Cu")
		(net "CLK_25M_NSSC_CPU1_DN")
	)
	(segment
		(start 187.072016 -150.993856)
		(end 186.895994 -150.993856)
		(width 0.13208)
		(layer "F.Cu")
		(net "CLK_25M_NSSC_CPU1_DN")
	)
	(via
		(at 237.178342 -134.741666)
		(size 0.508)
		(drill 0.254)
		(layers "F.Cu" "B.Cu")
		(net "CLK_25M_NSSC_CPU1_DN")
	)
	(via
		(at 187.12434 -153.375868)
		(size 0.508)
		(drill 0.254)
		(layers "F.Cu" "B.Cu")
		(net "CLK_25M_NSSC_CPU1_DN")
	)
	(via
		(at 121.508012 -238.225584)
		(size 0.4572)
		(drill 0.2032)
		(layers "F.Cu" "B.Cu")
		(net "CLK_25M_NSSC_CPU1_DN")
	)
	(segment
		(start 125.080014 -238.549942)
		(end 125.065282 -238.541306)
		(width 0.0889)
		(layer "B.Cu")
		(net "CLK_25M_NSSC_CPU1_DN")
	)
	(segment
		(start 137.65403 -238.473996)
		(end 137.014966 -238.473996)
		(width 0.0889)
		(layer "B.Cu")
		(net "CLK_25M_NSSC_CPU1_DN")
	)
	(segment
		(start 127.899414 -238.549942)
		(end 127.884682 -238.541306)
		(width 0.0889)
		(layer "B.Cu")
		(net "CLK_25M_NSSC_CPU1_DN")
	)
	(segment
		(start 237.178342 -134.774686)
		(end 236.601762 -135.351266)
		(width 0.13208)
		(layer "B.Cu")
		(net "CLK_25M_NSSC_CPU1_DN")
	)
	(segment
		(start 121.75363 -238.520478)
		(end 121.664476 -238.496602)
		(width 0.0889)
		(layer "B.Cu")
		(net "CLK_25M_NSSC_CPU1_DN")
	)
	(segment
		(start 137.710418 -238.439706)
		(end 137.68832 -238.439706)
		(width 0.0889)
		(layer "B.Cu")
		(net "CLK_25M_NSSC_CPU1_DN")
	)
	(segment
		(start 164.47008 -191.209168)
		(end 164.47008 -198.321676)
		(width 0.13208)
		(layer "B.Cu")
		(net "CLK_25M_NSSC_CPU1_DN")
	)
	(segment
		(start 163.15944 -235.007404)
		(end 162.078162 -236.088682)
		(width 0.13208)
		(layer "B.Cu")
		(net "CLK_25M_NSSC_CPU1_DN")
	)
	(segment
		(start 130.718814 -238.549942)
		(end 130.704082 -238.541306)
		(width 0.0889)
		(layer "B.Cu")
		(net "CLK_25M_NSSC_CPU1_DN")
	)
	(segment
		(start 237.178342 -134.741666)
		(end 237.178342 -134.774686)
		(width 0.13208)
		(layer "B.Cu")
		(net "CLK_25M_NSSC_CPU1_DN")
	)
	(segment
		(start 121.664476 -238.496602)
		(end 121.508012 -238.225584)
		(width 0.0889)
		(layer "B.Cu")
		(net "CLK_25M_NSSC_CPU1_DN")
	)
	(segment
		(start 186.177936 -153.673048)
		(end 180.484018 -159.366712)
		(width 0.13208)
		(layer "B.Cu")
		(net "CLK_25M_NSSC_CPU1_DN")
	)
	(segment
		(start 126.959614 -238.549942)
		(end 126.9492 -238.543846)
		(width 0.0889)
		(layer "B.Cu")
		(net "CLK_25M_NSSC_CPU1_DN")
	)
	(segment
		(start 164.033708 -199.375268)
		(end 163.15944 -200.249282)
		(width 0.13208)
		(layer "B.Cu")
		(net "CLK_25M_NSSC_CPU1_DN")
	)
	(segment
		(start 124.140214 -238.549942)
		(end 124.125482 -238.541306)
		(width 0.0889)
		(layer "B.Cu")
		(net "CLK_25M_NSSC_CPU1_DN")
	)
	(segment
		(start 137.68832 -238.439706)
		(end 137.65403 -238.473996)
		(width 0.0889)
		(layer "B.Cu")
		(net "CLK_25M_NSSC_CPU1_DN")
	)
	(segment
		(start 186.82716 -153.673048)
		(end 186.177936 -153.673048)
		(width 0.13208)
		(layer "B.Cu")
		(net "CLK_25M_NSSC_CPU1_DN")
	)
	(segment
		(start 173.052994 -170.487594)
		(end 164.47008 -191.209168)
		(width 0.13208)
		(layer "B.Cu")
		(net "CLK_25M_NSSC_CPU1_DN")
	)
	(segment
		(start 131.658614 -238.549942)
		(end 131.643882 -238.541306)
		(width 0.0889)
		(layer "B.Cu")
		(net "CLK_25M_NSSC_CPU1_DN")
	)
	(segment
		(start 187.12434 -153.375868)
		(end 186.82716 -153.673048)
		(width 0.13208)
		(layer "B.Cu")
		(net "CLK_25M_NSSC_CPU1_DN")
	)
	(segment
		(start 162.071812 -236.091222)
		(end 159.741108 -237.05693)
		(width 0.13208)
		(layer "B.Cu")
		(net "CLK_25M_NSSC_CPU1_DN")
	)
	(segment
		(start 126.020068 -238.549942)
		(end 126.009654 -238.543846)
		(width 0.0889)
		(layer "B.Cu")
		(net "CLK_25M_NSSC_CPU1_DN")
	)
	(segment
		(start 180.469794 -159.387794)
		(end 173.052994 -170.487594)
		(width 0.13208)
		(layer "B.Cu")
		(net "CLK_25M_NSSC_CPU1_DN")
	)
	(segment
		(start 159.741108 -237.05693)
		(end 152.63876 -237.05693)
		(width 0.13208)
		(layer "B.Cu")
		(net "CLK_25M_NSSC_CPU1_DN")
	)
	(segment
		(start 128.839214 -238.549942)
		(end 128.824482 -238.541306)
		(width 0.0889)
		(layer "B.Cu")
		(net "CLK_25M_NSSC_CPU1_DN")
	)
	(segment
		(start 236.601762 -135.351266)
		(end 236.601762 -135.401558)
		(width 0.13208)
		(layer "B.Cu")
		(net "CLK_25M_NSSC_CPU1_DN")
	)
	(segment
		(start 122.260614 -238.549942)
		(end 122.245882 -238.541306)
		(width 0.0889)
		(layer "B.Cu")
		(net "CLK_25M_NSSC_CPU1_DN")
	)
	(segment
		(start 149.300438 -238.439706)
		(end 137.710418 -238.439706)
		(width 0.13208)
		(layer "B.Cu")
		(net "CLK_25M_NSSC_CPU1_DN")
	)
	(segment
		(start 152.63876 -237.05693)
		(end 149.300438 -238.439706)
		(width 0.13208)
		(layer "B.Cu")
		(net "CLK_25M_NSSC_CPU1_DN")
	)
	(segment
		(start 132.598668 -238.549942)
		(end 132.588254 -238.543846)
		(width 0.0889)
		(layer "B.Cu")
		(net "CLK_25M_NSSC_CPU1_DN")
	)
	(segment
		(start 180.484018 -159.366712)
		(end 180.469794 -159.387794)
		(width 0.13208)
		(layer "B.Cu")
		(net "CLK_25M_NSSC_CPU1_DN")
	)
	(segment
		(start 162.078162 -236.088682)
		(end 162.071812 -236.091222)
		(width 0.13208)
		(layer "B.Cu")
		(net "CLK_25M_NSSC_CPU1_DN")
	)
	(segment
		(start 163.15944 -200.249282)
		(end 163.15944 -235.007404)
		(width 0.13208)
		(layer "B.Cu")
		(net "CLK_25M_NSSC_CPU1_DN")
	)
	(segment
		(start 164.47008 -198.321676)
		(end 164.033708 -199.375268)
		(width 0.13208)
		(layer "B.Cu")
		(net "CLK_25M_NSSC_CPU1_DN")
	)
	(arc
		(start 136.965944 -238.476028)
		(mid 136.845045 -238.500157)
		(end 136.732264 -238.549942)
		(width 0.0889)
		(layer "B.Cu")
		(net "CLK_25M_NSSC_CPU1_DN")
	)
	(arc
		(start 124.51461 -238.549942)
		(mid 124.327412 -238.600085)
		(end 124.140214 -238.549942)
		(width 0.0889)
		(layer "B.Cu")
		(net "CLK_25M_NSSC_CPU1_DN")
	)
	(arc
		(start 133.538468 -238.549942)
		(mid 133.255766 -238.474166)
		(end 132.973064 -238.549942)
		(width 0.0889)
		(layer "B.Cu")
		(net "CLK_25M_NSSC_CPU1_DN")
	)
	(arc
		(start 133.912864 -238.549942)
		(mid 133.725666 -238.600085)
		(end 133.538468 -238.549942)
		(width 0.0889)
		(layer "B.Cu")
		(net "CLK_25M_NSSC_CPU1_DN")
	)
	(arc
		(start 122.245882 -238.541306)
		(mid 122.012967 -238.475095)
		(end 121.773696 -238.51235)
		(width 0.0889)
		(layer "B.Cu")
		(net "CLK_25M_NSSC_CPU1_DN")
	)
	(arc
		(start 134.478268 -238.549942)
		(mid 134.195566 -238.474166)
		(end 133.912864 -238.549942)
		(width 0.0889)
		(layer "B.Cu")
		(net "CLK_25M_NSSC_CPU1_DN")
	)
	(arc
		(start 130.704082 -238.541306)
		(mid 130.427607 -238.473986)
		(end 130.15341 -238.549942)
		(width 0.0889)
		(layer "B.Cu")
		(net "CLK_25M_NSSC_CPU1_DN")
	)
	(arc
		(start 121.773696 -238.51235)
		(mid 121.763625 -238.516319)
		(end 121.75363 -238.520478)
		(width 0.0889)
		(layer "B.Cu")
		(net "CLK_25M_NSSC_CPU1_DN")
	)
	(arc
		(start 136.357868 -238.549942)
		(mid 136.075166 -238.474166)
		(end 135.792464 -238.549942)
		(width 0.0889)
		(layer "B.Cu")
		(net "CLK_25M_NSSC_CPU1_DN")
	)
	(arc
		(start 127.33401 -238.549942)
		(mid 127.146812 -238.600085)
		(end 126.959614 -238.549942)
		(width 0.0889)
		(layer "B.Cu")
		(net "CLK_25M_NSSC_CPU1_DN")
	)
	(arc
		(start 130.15341 -238.549942)
		(mid 129.966212 -238.600085)
		(end 129.779014 -238.549942)
		(width 0.0889)
		(layer "B.Cu")
		(net "CLK_25M_NSSC_CPU1_DN")
	)
	(arc
		(start 129.21361 -238.549942)
		(mid 129.026412 -238.600085)
		(end 128.839214 -238.549942)
		(width 0.0889)
		(layer "B.Cu")
		(net "CLK_25M_NSSC_CPU1_DN")
	)
	(arc
		(start 132.588254 -238.543846)
		(mid 132.309822 -238.474)
		(end 132.03301 -238.549942)
		(width 0.0889)
		(layer "B.Cu")
		(net "CLK_25M_NSSC_CPU1_DN")
	)
	(arc
		(start 137.014966 -238.473996)
		(mid 136.990433 -238.474484)
		(end 136.965944 -238.476028)
		(width 0.0889)
		(layer "B.Cu")
		(net "CLK_25M_NSSC_CPU1_DN")
	)
	(arc
		(start 134.852664 -238.549942)
		(mid 134.665466 -238.600085)
		(end 134.478268 -238.549942)
		(width 0.0889)
		(layer "B.Cu")
		(net "CLK_25M_NSSC_CPU1_DN")
	)
	(arc
		(start 123.200414 -238.549942)
		(mid 122.917712 -238.474166)
		(end 122.63501 -238.549942)
		(width 0.0889)
		(layer "B.Cu")
		(net "CLK_25M_NSSC_CPU1_DN")
	)
	(arc
		(start 123.57481 -238.549942)
		(mid 123.387612 -238.600085)
		(end 123.200414 -238.549942)
		(width 0.0889)
		(layer "B.Cu")
		(net "CLK_25M_NSSC_CPU1_DN")
	)
	(arc
		(start 129.779014 -238.549942)
		(mid 129.496312 -238.474166)
		(end 129.21361 -238.549942)
		(width 0.0889)
		(layer "B.Cu")
		(net "CLK_25M_NSSC_CPU1_DN")
	)
	(arc
		(start 131.643882 -238.541306)
		(mid 131.367407 -238.473986)
		(end 131.09321 -238.549942)
		(width 0.0889)
		(layer "B.Cu")
		(net "CLK_25M_NSSC_CPU1_DN")
	)
	(arc
		(start 126.9492 -238.543846)
		(mid 126.671022 -238.474123)
		(end 126.394464 -238.549942)
		(width 0.0889)
		(layer "B.Cu")
		(net "CLK_25M_NSSC_CPU1_DN")
	)
	(arc
		(start 135.418068 -238.549942)
		(mid 135.135366 -238.474166)
		(end 134.852664 -238.549942)
		(width 0.0889)
		(layer "B.Cu")
		(net "CLK_25M_NSSC_CPU1_DN")
	)
	(arc
		(start 126.394464 -238.549942)
		(mid 126.207266 -238.600085)
		(end 126.020068 -238.549942)
		(width 0.0889)
		(layer "B.Cu")
		(net "CLK_25M_NSSC_CPU1_DN")
	)
	(arc
		(start 132.973064 -238.549942)
		(mid 132.785866 -238.600085)
		(end 132.598668 -238.549942)
		(width 0.0889)
		(layer "B.Cu")
		(net "CLK_25M_NSSC_CPU1_DN")
	)
	(arc
		(start 128.27381 -238.549942)
		(mid 128.086612 -238.600085)
		(end 127.899414 -238.549942)
		(width 0.0889)
		(layer "B.Cu")
		(net "CLK_25M_NSSC_CPU1_DN")
	)
	(arc
		(start 136.732264 -238.549942)
		(mid 136.545066 -238.600085)
		(end 136.357868 -238.549942)
		(width 0.0889)
		(layer "B.Cu")
		(net "CLK_25M_NSSC_CPU1_DN")
	)
	(arc
		(start 127.884682 -238.541306)
		(mid 127.608207 -238.473986)
		(end 127.33401 -238.549942)
		(width 0.0889)
		(layer "B.Cu")
		(net "CLK_25M_NSSC_CPU1_DN")
	)
	(arc
		(start 128.824482 -238.541306)
		(mid 128.548007 -238.473986)
		(end 128.27381 -238.549942)
		(width 0.0889)
		(layer "B.Cu")
		(net "CLK_25M_NSSC_CPU1_DN")
	)
	(arc
		(start 132.03301 -238.549942)
		(mid 131.845812 -238.600085)
		(end 131.658614 -238.549942)
		(width 0.0889)
		(layer "B.Cu")
		(net "CLK_25M_NSSC_CPU1_DN")
	)
	(arc
		(start 124.125482 -238.541306)
		(mid 123.849007 -238.473986)
		(end 123.57481 -238.549942)
		(width 0.0889)
		(layer "B.Cu")
		(net "CLK_25M_NSSC_CPU1_DN")
	)
	(arc
		(start 125.45441 -238.549942)
		(mid 125.267212 -238.600085)
		(end 125.080014 -238.549942)
		(width 0.0889)
		(layer "B.Cu")
		(net "CLK_25M_NSSC_CPU1_DN")
	)
	(arc
		(start 131.09321 -238.549942)
		(mid 130.906012 -238.600085)
		(end 130.718814 -238.549942)
		(width 0.0889)
		(layer "B.Cu")
		(net "CLK_25M_NSSC_CPU1_DN")
	)
	(arc
		(start 122.63501 -238.549942)
		(mid 122.447812 -238.600085)
		(end 122.260614 -238.549942)
		(width 0.0889)
		(layer "B.Cu")
		(net "CLK_25M_NSSC_CPU1_DN")
	)
	(arc
		(start 125.065282 -238.541306)
		(mid 124.788807 -238.473986)
		(end 124.51461 -238.549942)
		(width 0.0889)
		(layer "B.Cu")
		(net "CLK_25M_NSSC_CPU1_DN")
	)
	(arc
		(start 135.792464 -238.549942)
		(mid 135.605266 -238.600085)
		(end 135.418068 -238.549942)
		(width 0.0889)
		(layer "B.Cu")
		(net "CLK_25M_NSSC_CPU1_DN")
	)
	(arc
		(start 126.009654 -238.543846)
		(mid 125.731222 -238.474)
		(end 125.45441 -238.549942)
		(width 0.0889)
		(layer "B.Cu")
		(net "CLK_25M_NSSC_CPU1_DN")
	)
	(segment
		(start 343.58199 -137.547858)
		(end 343.61628 -137.720578)
		(width 0.13208)
		(layer "F.Cu")
		(net "CLK_25M_NSSC_CPU0_DP")
	)
	(segment
		(start 345.180158 -138.765534)
		(end 345.352624 -138.731244)
		(width 0.13208)
		(layer "F.Cu")
		(net "CLK_25M_NSSC_CPU0_DP")
	)
	(segment
		(start 343.941654 -137.938256)
		(end 344.114374 -137.903712)
		(width 0.13208)
		(layer "F.Cu")
		(net "CLK_25M_NSSC_CPU0_DP")
	)
	(segment
		(start 373.1895 -160.581848)
		(end 372.88724 -160.884108)
		(width 0.13208)
		(layer "F.Cu")
		(net "CLK_25M_NSSC_CPU0_DP")
	)
	(segment
		(start 371.694964 -157.344872)
		(end 372.267988 -157.917896)
		(width 0.13208)
		(layer "F.Cu")
		(net "CLK_25M_NSSC_CPU0_DP")
	)
	(segment
		(start 342.66505 -137.08507)
		(end 342.990424 -137.302748)
		(width 0.13208)
		(layer "F.Cu")
		(net "CLK_25M_NSSC_CPU0_DP")
	)
	(segment
		(start 347.481906 -140.303504)
		(end 347.654626 -140.269214)
		(width 0.13208)
		(layer "F.Cu")
		(net "CLK_25M_NSSC_CPU0_DP")
	)
	(segment
		(start 343.163144 -137.268204)
		(end 343.58199 -137.547858)
		(width 0.13208)
		(layer "F.Cu")
		(net "CLK_25M_NSSC_CPU0_DP")
	)
	(segment
		(start 343.61628 -137.720578)
		(end 343.941654 -137.938256)
		(width 0.13208)
		(layer "F.Cu")
		(net "CLK_25M_NSSC_CPU0_DP")
	)
	(segment
		(start 344.82024 -138.37539)
		(end 344.85453 -138.547856)
		(width 0.13208)
		(layer "F.Cu")
		(net "CLK_25M_NSSC_CPU0_DP")
	)
	(segment
		(start 347.122242 -139.91336)
		(end 347.156532 -140.08608)
		(width 0.13208)
		(layer "F.Cu")
		(net "CLK_25M_NSSC_CPU0_DP")
	)
	(segment
		(start 338.38896 -136.266936)
		(end 338.81822 -135.837676)
		(width 0.13208)
		(layer "F.Cu")
		(net "CLK_25M_NSSC_CPU0_DP")
	)
	(segment
		(start 372.564152 -158.544006)
		(end 372.50497 -158.709868)
		(width 0.13208)
		(layer "F.Cu")
		(net "CLK_25M_NSSC_CPU0_DP")
	)
	(segment
		(start 369.91798 -239.57534)
		(end 369.918234 -239.575086)
		(width 0.13208)
		(layer "F.Cu")
		(net "CLK_25M_NSSC_CPU0_DP")
	)
	(segment
		(start 342.990424 -137.302748)
		(end 343.163144 -137.268204)
		(width 0.13208)
		(layer "F.Cu")
		(net "CLK_25M_NSSC_CPU0_DP")
	)
	(segment
		(start 340.616032 -135.837676)
		(end 341.358982 -136.062974)
		(width 0.13208)
		(layer "F.Cu")
		(net "CLK_25M_NSSC_CPU0_DP")
	)
	(segment
		(start 341.708486 -136.2964)
		(end 341.74303 -136.46912)
		(width 0.13208)
		(layer "F.Cu")
		(net "CLK_25M_NSSC_CPU0_DP")
	)
	(segment
		(start 372.50497 -158.709868)
		(end 372.672102 -159.06369)
		(width 0.13208)
		(layer "F.Cu")
		(net "CLK_25M_NSSC_CPU0_DP")
	)
	(segment
		(start 342.630506 -136.91235)
		(end 342.66505 -137.08507)
		(width 0.13208)
		(layer "F.Cu")
		(net "CLK_25M_NSSC_CPU0_DP")
	)
	(segment
		(start 342.068404 -136.686798)
		(end 342.241124 -136.652254)
		(width 0.13208)
		(layer "F.Cu")
		(net "CLK_25M_NSSC_CPU0_DP")
	)
	(segment
		(start 338.618322 -137.02919)
		(end 338.38896 -136.799828)
		(width 0.13208)
		(layer "F.Cu")
		(net "CLK_25M_NSSC_CPU0_DP")
	)
	(segment
		(start 338.81822 -135.837676)
		(end 340.616032 -135.837676)
		(width 0.13208)
		(layer "F.Cu")
		(net "CLK_25M_NSSC_CPU0_DP")
	)
	(segment
		(start 344.85453 -138.547856)
		(end 345.180158 -138.765534)
		(width 0.13208)
		(layer "F.Cu")
		(net "CLK_25M_NSSC_CPU0_DP")
	)
	(segment
		(start 342.241124 -136.652254)
		(end 342.630506 -136.91235)
		(width 0.13208)
		(layer "F.Cu")
		(net "CLK_25M_NSSC_CPU0_DP")
	)
	(segment
		(start 372.267988 -157.917896)
		(end 372.564152 -158.544006)
		(width 0.13208)
		(layer "F.Cu")
		(net "CLK_25M_NSSC_CPU0_DP")
	)
	(segment
		(start 369.442238 -155.092146)
		(end 371.242336 -156.892244)
		(width 0.13208)
		(layer "F.Cu")
		(net "CLK_25M_NSSC_CPU0_DP")
	)
	(segment
		(start 347.156532 -140.08608)
		(end 347.481906 -140.303504)
		(width 0.13208)
		(layer "F.Cu")
		(net "CLK_25M_NSSC_CPU0_DP")
	)
	(segment
		(start 346.449142 -139.46378)
		(end 347.122242 -139.91336)
		(width 0.13208)
		(layer "F.Cu")
		(net "CLK_25M_NSSC_CPU0_DP")
	)
	(segment
		(start 344.114374 -137.903712)
		(end 344.82024 -138.37539)
		(width 0.13208)
		(layer "F.Cu")
		(net "CLK_25M_NSSC_CPU0_DP")
	)
	(segment
		(start 338.38896 -136.799828)
		(end 338.38896 -136.266936)
		(width 0.13208)
		(layer "F.Cu")
		(net "CLK_25M_NSSC_CPU0_DP")
	)
	(segment
		(start 371.242336 -156.892244)
		(end 371.242336 -157.068266)
		(width 0.13208)
		(layer "F.Cu")
		(net "CLK_25M_NSSC_CPU0_DP")
	)
	(segment
		(start 341.358982 -136.062974)
		(end 341.708486 -136.2964)
		(width 0.13208)
		(layer "F.Cu")
		(net "CLK_25M_NSSC_CPU0_DP")
	)
	(segment
		(start 371.242336 -157.068266)
		(end 371.518942 -157.344872)
		(width 0.13208)
		(layer "F.Cu")
		(net "CLK_25M_NSSC_CPU0_DP")
	)
	(segment
		(start 372.672102 -159.06369)
		(end 372.838218 -159.122872)
		(width 0.13208)
		(layer "F.Cu")
		(net "CLK_25M_NSSC_CPU0_DP")
	)
	(segment
		(start 345.951048 -139.280646)
		(end 346.276422 -139.498324)
		(width 0.13208)
		(layer "F.Cu")
		(net "CLK_25M_NSSC_CPU0_DP")
	)
	(segment
		(start 346.276422 -139.498324)
		(end 346.449142 -139.46378)
		(width 0.13208)
		(layer "F.Cu")
		(net "CLK_25M_NSSC_CPU0_DP")
	)
	(segment
		(start 371.518942 -157.344872)
		(end 371.694964 -157.344872)
		(width 0.13208)
		(layer "F.Cu")
		(net "CLK_25M_NSSC_CPU0_DP")
	)
	(segment
		(start 347.654626 -140.269214)
		(end 367.699544 -153.662126)
		(width 0.13208)
		(layer "F.Cu")
		(net "CLK_25M_NSSC_CPU0_DP")
	)
	(segment
		(start 369.918234 -239.575086)
		(end 369.918234 -239.0394)
		(width 0.13208)
		(layer "F.Cu")
		(net "CLK_25M_NSSC_CPU0_DP")
	)
	(segment
		(start 372.838218 -159.122872)
		(end 373.1895 -159.865568)
		(width 0.13208)
		(layer "F.Cu")
		(net "CLK_25M_NSSC_CPU0_DP")
	)
	(segment
		(start 338.618322 -137.172446)
		(end 338.618322 -137.02919)
		(width 0.13208)
		(layer "F.Cu")
		(net "CLK_25M_NSSC_CPU0_DP")
	)
	(segment
		(start 373.1895 -159.865568)
		(end 373.1895 -160.581848)
		(width 0.13208)
		(layer "F.Cu")
		(net "CLK_25M_NSSC_CPU0_DP")
	)
	(segment
		(start 341.74303 -136.46912)
		(end 342.068404 -136.686798)
		(width 0.13208)
		(layer "F.Cu")
		(net "CLK_25M_NSSC_CPU0_DP")
	)
	(segment
		(start 345.916758 -139.107926)
		(end 345.951048 -139.280646)
		(width 0.13208)
		(layer "F.Cu")
		(net "CLK_25M_NSSC_CPU0_DP")
	)
	(segment
		(start 367.699544 -153.662126)
		(end 369.442238 -155.092146)
		(width 0.13208)
		(layer "F.Cu")
		(net "CLK_25M_NSSC_CPU0_DP")
	)
	(segment
		(start 345.352624 -138.731244)
		(end 345.916758 -139.107926)
		(width 0.13208)
		(layer "F.Cu")
		(net "CLK_25M_NSSC_CPU0_DP")
	)
	(via
		(at 338.618322 -137.172446)
		(size 0.508)
		(drill 0.254)
		(layers "F.Cu" "B.Cu")
		(net "CLK_25M_NSSC_CPU0_DP")
	)
	(via
		(at 369.918234 -239.0394)
		(size 0.4572)
		(drill 0.2032)
		(layers "F.Cu" "B.Cu")
		(net "CLK_25M_NSSC_CPU0_DP")
	)
	(via
		(at 372.88724 -160.884108)
		(size 0.508)
		(drill 0.254)
		(layers "F.Cu" "B.Cu")
		(net "CLK_25M_NSSC_CPU0_DP")
	)
	(segment
		(start 369.731036 -239.363758)
		(end 369.56111 -239.27181)
		(width 0.0889)
		(layer "B.Cu")
		(net "CLK_25M_NSSC_CPU0_DP")
	)
	(segment
		(start 394.544804 -233.498898)
		(end 394.12164 -233.922062)
		(width 0.13208)
		(layer "B.Cu")
		(net "CLK_25M_NSSC_CPU0_DP")
	)
	(segment
		(start 391.983214 -235.888022)
		(end 391.983214 -236.060488)
		(width 0.13208)
		(layer "B.Cu")
		(net "CLK_25M_NSSC_CPU0_DP")
	)
	(segment
		(start 387.655308 -238.439706)
		(end 385.769358 -238.439706)
		(width 0.13208)
		(layer "B.Cu")
		(net "CLK_25M_NSSC_CPU0_DP")
	)
	(segment
		(start 373.020082 -238.549942)
		(end 373.00535 -238.541306)
		(width 0.0889)
		(layer "B.Cu")
		(net "CLK_25M_NSSC_CPU0_DP")
	)
	(segment
		(start 377.766834 -171.506896)
		(end 379.543056 -174.470568)
		(width 0.13208)
		(layer "B.Cu")
		(net "CLK_25M_NSSC_CPU0_DP")
	)
	(segment
		(start 396.033752 -232.00995)
		(end 395.7574 -232.286302)
		(width 0.13208)
		(layer "B.Cu")
		(net "CLK_25M_NSSC_CPU0_DP")
	)
	(segment
		(start 394.544804 -233.326432)
		(end 394.544804 -233.498898)
		(width 0.13208)
		(layer "B.Cu")
		(net "CLK_25M_NSSC_CPU0_DP")
	)
	(segment
		(start 372.88724 -160.884108)
		(end 373.1895 -161.186368)
		(width 0.13208)
		(layer "B.Cu")
		(net "CLK_25M_NSSC_CPU0_DP")
	)
	(segment
		(start 393.04468 -192.472056)
		(end 398.19834 -197.625716)
		(width 0.13208)
		(layer "B.Cu")
		(net "CLK_25M_NSSC_CPU0_DP")
	)
	(segment
		(start 385.71297 -238.473996)
		(end 384.955034 -238.473996)
		(width 0.0889)
		(layer "B.Cu")
		(net "CLK_25M_NSSC_CPU0_DP")
	)
	(segment
		(start 370.29263 -239.029494)
		(end 370.29263 -239.048036)
		(width 0.0889)
		(layer "B.Cu")
		(net "CLK_25M_NSSC_CPU0_DP")
	)
	(segment
		(start 390.981184 -237.062518)
		(end 387.655308 -238.439706)
		(width 0.13208)
		(layer "B.Cu")
		(net "CLK_25M_NSSC_CPU0_DP")
	)
	(segment
		(start 369.5446 -238.82223)
		(end 369.653312 -238.759492)
		(width 0.0889)
		(layer "B.Cu")
		(net "CLK_25M_NSSC_CPU0_DP")
	)
	(segment
		(start 374.398286 -164.897308)
		(end 377.159012 -169.502836)
		(width 0.13208)
		(layer "B.Cu")
		(net "CLK_25M_NSSC_CPU0_DP")
	)
	(segment
		(start 369.471956 -238.894874)
		(end 369.5446 -238.82223)
		(width 0.0889)
		(layer "B.Cu")
		(net "CLK_25M_NSSC_CPU0_DP")
	)
	(segment
		(start 375.839482 -238.549942)
		(end 375.82475 -238.541306)
		(width 0.0889)
		(layer "B.Cu")
		(net "CLK_25M_NSSC_CPU0_DP")
	)
	(segment
		(start 394.12164 -233.922062)
		(end 393.949174 -233.922062)
		(width 0.13208)
		(layer "B.Cu")
		(net "CLK_25M_NSSC_CPU0_DP")
	)
	(segment
		(start 373.1895 -161.979102)
		(end 374.398286 -164.897308)
		(width 0.13208)
		(layer "B.Cu")
		(net "CLK_25M_NSSC_CPU0_DP")
	)
	(segment
		(start 398.19834 -197.625716)
		(end 398.19834 -229.409244)
		(width 0.13208)
		(layer "B.Cu")
		(net "CLK_25M_NSSC_CPU0_DP")
	)
	(segment
		(start 377.159012 -169.502836)
		(end 377.766834 -171.506896)
		(width 0.13208)
		(layer "B.Cu")
		(net "CLK_25M_NSSC_CPU0_DP")
	)
	(segment
		(start 397.386302 -230.6574)
		(end 397.21028 -230.6574)
		(width 0.13208)
		(layer "B.Cu")
		(net "CLK_25M_NSSC_CPU0_DP")
	)
	(segment
		(start 380.538736 -238.549942)
		(end 380.528322 -238.543846)
		(width 0.0889)
		(layer "B.Cu")
		(net "CLK_25M_NSSC_CPU0_DP")
	)
	(segment
		(start 392.761724 -235.281978)
		(end 392.43254 -235.611162)
		(width 0.13208)
		(layer "B.Cu")
		(net "CLK_25M_NSSC_CPU0_DP")
	)
	(segment
		(start 338.618322 -137.172446)
		(end 338.618322 -137.279126)
		(width 0.13208)
		(layer "B.Cu")
		(net "CLK_25M_NSSC_CPU0_DP")
	)
	(segment
		(start 376.779282 -238.549942)
		(end 376.76455 -238.541306)
		(width 0.0889)
		(layer "B.Cu")
		(net "CLK_25M_NSSC_CPU0_DP")
	)
	(segment
		(start 391.983214 -236.060488)
		(end 391.706862 -236.33684)
		(width 0.13208)
		(layer "B.Cu")
		(net "CLK_25M_NSSC_CPU0_DP")
	)
	(segment
		(start 398.19834 -229.409244)
		(end 397.88973 -230.153972)
		(width 0.13208)
		(layer "B.Cu")
		(net "CLK_25M_NSSC_CPU0_DP")
	)
	(segment
		(start 374.899682 -238.549942)
		(end 374.889268 -238.543846)
		(width 0.0889)
		(layer "B.Cu")
		(net "CLK_25M_NSSC_CPU0_DP")
	)
	(segment
		(start 393.949174 -233.922062)
		(end 393.672314 -234.198922)
		(width 0.13208)
		(layer "B.Cu")
		(net "CLK_25M_NSSC_CPU0_DP")
	)
	(segment
		(start 397.88973 -230.153972)
		(end 397.386302 -230.6574)
		(width 0.13208)
		(layer "B.Cu")
		(net "CLK_25M_NSSC_CPU0_DP")
	)
	(segment
		(start 395.584934 -232.286302)
		(end 395.308074 -232.563162)
		(width 0.13208)
		(layer "B.Cu")
		(net "CLK_25M_NSSC_CPU0_DP")
	)
	(segment
		(start 396.033752 -231.837484)
		(end 396.033752 -232.00995)
		(width 0.13208)
		(layer "B.Cu")
		(net "CLK_25M_NSSC_CPU0_DP")
	)
	(segment
		(start 373.960136 -238.549942)
		(end 373.949722 -238.543846)
		(width 0.0889)
		(layer "B.Cu")
		(net "CLK_25M_NSSC_CPU0_DP")
	)
	(segment
		(start 391.706862 -236.33684)
		(end 391.534396 -236.33684)
		(width 0.13208)
		(layer "B.Cu")
		(net "CLK_25M_NSSC_CPU0_DP")
	)
	(segment
		(start 379.598682 -238.549942)
		(end 379.58395 -238.541306)
		(width 0.0889)
		(layer "B.Cu")
		(net "CLK_25M_NSSC_CPU0_DP")
	)
	(segment
		(start 372.080282 -238.549942)
		(end 372.06555 -238.541306)
		(width 0.0889)
		(layer "B.Cu")
		(net "CLK_25M_NSSC_CPU0_DP")
	)
	(segment
		(start 392.43254 -235.611162)
		(end 392.260074 -235.611162)
		(width 0.13208)
		(layer "B.Cu")
		(net "CLK_25M_NSSC_CPU0_DP")
	)
	(segment
		(start 385.74726 -238.439706)
		(end 385.71297 -238.473996)
		(width 0.0889)
		(layer "B.Cu")
		(net "CLK_25M_NSSC_CPU0_DP")
	)
	(segment
		(start 389.862314 -184.789826)
		(end 393.04468 -192.472056)
		(width 0.13208)
		(layer "B.Cu")
		(net "CLK_25M_NSSC_CPU0_DP")
	)
	(segment
		(start 397.21028 -230.6574)
		(end 396.940532 -230.927148)
		(width 0.13208)
		(layer "B.Cu")
		(net "CLK_25M_NSSC_CPU0_DP")
	)
	(segment
		(start 378.658882 -238.549942)
		(end 378.64415 -238.541306)
		(width 0.0889)
		(layer "B.Cu")
		(net "CLK_25M_NSSC_CPU0_DP")
	)
	(segment
		(start 391.257536 -236.6137)
		(end 391.257536 -236.786166)
		(width 0.13208)
		(layer "B.Cu")
		(net "CLK_25M_NSSC_CPU0_DP")
	)
	(segment
		(start 392.761724 -235.109512)
		(end 392.761724 -235.281978)
		(width 0.13208)
		(layer "B.Cu")
		(net "CLK_25M_NSSC_CPU0_DP")
	)
	(segment
		(start 396.310612 -231.560624)
		(end 396.033752 -231.837484)
		(width 0.13208)
		(layer "B.Cu")
		(net "CLK_25M_NSSC_CPU0_DP")
	)
	(segment
		(start 395.7574 -232.286302)
		(end 395.584934 -232.286302)
		(width 0.13208)
		(layer "B.Cu")
		(net "CLK_25M_NSSC_CPU0_DP")
	)
	(segment
		(start 393.672314 -234.371388)
		(end 393.21105 -234.832652)
		(width 0.13208)
		(layer "B.Cu")
		(net "CLK_25M_NSSC_CPU0_DP")
	)
	(segment
		(start 369.471956 -239.182656)
		(end 369.471956 -238.894874)
		(width 0.0889)
		(layer "B.Cu")
		(net "CLK_25M_NSSC_CPU0_DP")
	)
	(segment
		(start 396.483078 -231.560624)
		(end 396.310612 -231.560624)
		(width 0.13208)
		(layer "B.Cu")
		(net "CLK_25M_NSSC_CPU0_DP")
	)
	(segment
		(start 393.21105 -234.832652)
		(end 393.038584 -234.832652)
		(width 0.13208)
		(layer "B.Cu")
		(net "CLK_25M_NSSC_CPU0_DP")
	)
	(segment
		(start 369.653312 -238.759492)
		(end 369.774978 -238.791496)
		(width 0.0889)
		(layer "B.Cu")
		(net "CLK_25M_NSSC_CPU0_DP")
	)
	(segment
		(start 391.257536 -236.786166)
		(end 390.981184 -237.062518)
		(width 0.13208)
		(layer "B.Cu")
		(net "CLK_25M_NSSC_CPU0_DP")
	)
	(segment
		(start 369.56111 -239.27181)
		(end 369.471956 -239.182656)
		(width 0.0889)
		(layer "B.Cu")
		(net "CLK_25M_NSSC_CPU0_DP")
	)
	(segment
		(start 395.308074 -232.735628)
		(end 394.99413 -233.049572)
		(width 0.13208)
		(layer "B.Cu")
		(net "CLK_25M_NSSC_CPU0_DP")
	)
	(segment
		(start 373.1895 -161.186368)
		(end 373.1895 -161.979102)
		(width 0.13208)
		(layer "B.Cu")
		(net "CLK_25M_NSSC_CPU0_DP")
	)
	(segment
		(start 394.821664 -233.049572)
		(end 394.544804 -233.326432)
		(width 0.13208)
		(layer "B.Cu")
		(net "CLK_25M_NSSC_CPU0_DP")
	)
	(segment
		(start 396.940532 -231.10317)
		(end 396.483078 -231.560624)
		(width 0.13208)
		(layer "B.Cu")
		(net "CLK_25M_NSSC_CPU0_DP")
	)
	(segment
		(start 393.672314 -234.198922)
		(end 393.672314 -234.371388)
		(width 0.13208)
		(layer "B.Cu")
		(net "CLK_25M_NSSC_CPU0_DP")
	)
	(segment
		(start 385.769358 -238.439706)
		(end 385.74726 -238.439706)
		(width 0.0889)
		(layer "B.Cu")
		(net "CLK_25M_NSSC_CPU0_DP")
	)
	(segment
		(start 379.543056 -174.470568)
		(end 389.862314 -184.789826)
		(width 0.13208)
		(layer "B.Cu")
		(net "CLK_25M_NSSC_CPU0_DP")
	)
	(segment
		(start 393.038584 -234.832652)
		(end 392.761724 -235.109512)
		(width 0.13208)
		(layer "B.Cu")
		(net "CLK_25M_NSSC_CPU0_DP")
	)
	(segment
		(start 396.940532 -230.927148)
		(end 396.940532 -231.10317)
		(width 0.13208)
		(layer "B.Cu")
		(net "CLK_25M_NSSC_CPU0_DP")
	)
	(segment
		(start 395.308074 -232.563162)
		(end 395.308074 -232.735628)
		(width 0.13208)
		(layer "B.Cu")
		(net "CLK_25M_NSSC_CPU0_DP")
	)
	(segment
		(start 369.774978 -238.791496)
		(end 369.918234 -239.0394)
		(width 0.0889)
		(layer "B.Cu")
		(net "CLK_25M_NSSC_CPU0_DP")
	)
	(segment
		(start 338.06511 -137.832338)
		(end 338.041742 -137.832338)
		(width 0.13208)
		(layer "B.Cu")
		(net "CLK_25M_NSSC_CPU0_DP")
	)
	(segment
		(start 392.260074 -235.611162)
		(end 391.983214 -235.888022)
		(width 0.13208)
		(layer "B.Cu")
		(net "CLK_25M_NSSC_CPU0_DP")
	)
	(segment
		(start 391.534396 -236.33684)
		(end 391.257536 -236.6137)
		(width 0.13208)
		(layer "B.Cu")
		(net "CLK_25M_NSSC_CPU0_DP")
	)
	(segment
		(start 394.99413 -233.049572)
		(end 394.821664 -233.049572)
		(width 0.13208)
		(layer "B.Cu")
		(net "CLK_25M_NSSC_CPU0_DP")
	)
	(segment
		(start 338.618322 -137.279126)
		(end 338.06511 -137.832338)
		(width 0.13208)
		(layer "B.Cu")
		(net "CLK_25M_NSSC_CPU0_DP")
	)
	(arc
		(start 375.274078 -238.549942)
		(mid 375.08688 -238.600085)
		(end 374.899682 -238.549942)
		(width 0.0889)
		(layer "B.Cu")
		(net "CLK_25M_NSSC_CPU0_DP")
	)
	(arc
		(start 378.64415 -238.541306)
		(mid 378.367675 -238.473986)
		(end 378.093478 -238.549942)
		(width 0.0889)
		(layer "B.Cu")
		(net "CLK_25M_NSSC_CPU0_DP")
	)
	(arc
		(start 379.973078 -238.549942)
		(mid 379.78588 -238.600085)
		(end 379.598682 -238.549942)
		(width 0.0889)
		(layer "B.Cu")
		(net "CLK_25M_NSSC_CPU0_DP")
	)
	(arc
		(start 373.394478 -238.549942)
		(mid 373.20728 -238.600085)
		(end 373.020082 -238.549942)
		(width 0.0889)
		(layer "B.Cu")
		(net "CLK_25M_NSSC_CPU0_DP")
	)
	(arc
		(start 380.528322 -238.543846)
		(mid 380.24989 -238.474)
		(end 379.973078 -238.549942)
		(width 0.0889)
		(layer "B.Cu")
		(net "CLK_25M_NSSC_CPU0_DP")
	)
	(arc
		(start 379.58395 -238.541306)
		(mid 379.307475 -238.473986)
		(end 379.033278 -238.549942)
		(width 0.0889)
		(layer "B.Cu")
		(net "CLK_25M_NSSC_CPU0_DP")
	)
	(arc
		(start 382.792732 -238.549942)
		(mid 382.605534 -238.600085)
		(end 382.418336 -238.549942)
		(width 0.0889)
		(layer "B.Cu")
		(net "CLK_25M_NSSC_CPU0_DP")
	)
	(arc
		(start 374.334532 -238.549942)
		(mid 374.147334 -238.600085)
		(end 373.960136 -238.549942)
		(width 0.0889)
		(layer "B.Cu")
		(net "CLK_25M_NSSC_CPU0_DP")
	)
	(arc
		(start 377.153678 -238.549942)
		(mid 376.96648 -238.600085)
		(end 376.779282 -238.549942)
		(width 0.0889)
		(layer "B.Cu")
		(net "CLK_25M_NSSC_CPU0_DP")
	)
	(arc
		(start 374.889268 -238.543846)
		(mid 374.61109 -238.474123)
		(end 374.334532 -238.549942)
		(width 0.0889)
		(layer "B.Cu")
		(net "CLK_25M_NSSC_CPU0_DP")
	)
	(arc
		(start 380.913132 -238.549942)
		(mid 380.725934 -238.600085)
		(end 380.538736 -238.549942)
		(width 0.0889)
		(layer "B.Cu")
		(net "CLK_25M_NSSC_CPU0_DP")
	)
	(arc
		(start 378.093478 -238.549942)
		(mid 377.90628 -238.600085)
		(end 377.719082 -238.549942)
		(width 0.0889)
		(layer "B.Cu")
		(net "CLK_25M_NSSC_CPU0_DP")
	)
	(arc
		(start 381.478536 -238.549942)
		(mid 381.195834 -238.474166)
		(end 380.913132 -238.549942)
		(width 0.0889)
		(layer "B.Cu")
		(net "CLK_25M_NSSC_CPU0_DP")
	)
	(arc
		(start 384.955034 -238.473996)
		(mid 384.930501 -238.474484)
		(end 384.906012 -238.476028)
		(width 0.0889)
		(layer "B.Cu")
		(net "CLK_25M_NSSC_CPU0_DP")
	)
	(arc
		(start 383.732532 -238.549942)
		(mid 383.545334 -238.600085)
		(end 383.358136 -238.549942)
		(width 0.0889)
		(layer "B.Cu")
		(net "CLK_25M_NSSC_CPU0_DP")
	)
	(arc
		(start 370.29263 -239.048036)
		(mid 370.101756 -239.365845)
		(end 369.731036 -239.363758)
		(width 0.0889)
		(layer "B.Cu")
		(net "CLK_25M_NSSC_CPU0_DP")
	)
	(arc
		(start 373.00535 -238.541306)
		(mid 372.728875 -238.473986)
		(end 372.454678 -238.549942)
		(width 0.0889)
		(layer "B.Cu")
		(net "CLK_25M_NSSC_CPU0_DP")
	)
	(arc
		(start 384.906012 -238.476028)
		(mid 384.785108 -238.500147)
		(end 384.672332 -238.549942)
		(width 0.0889)
		(layer "B.Cu")
		(net "CLK_25M_NSSC_CPU0_DP")
	)
	(arc
		(start 376.76455 -238.541306)
		(mid 376.488075 -238.473986)
		(end 376.213878 -238.549942)
		(width 0.0889)
		(layer "B.Cu")
		(net "CLK_25M_NSSC_CPU0_DP")
	)
	(arc
		(start 376.213878 -238.549942)
		(mid 376.02668 -238.600085)
		(end 375.839482 -238.549942)
		(width 0.0889)
		(layer "B.Cu")
		(net "CLK_25M_NSSC_CPU0_DP")
	)
	(arc
		(start 377.719082 -238.549942)
		(mid 377.43638 -238.474166)
		(end 377.153678 -238.549942)
		(width 0.0889)
		(layer "B.Cu")
		(net "CLK_25M_NSSC_CPU0_DP")
	)
	(arc
		(start 372.454678 -238.549942)
		(mid 372.26748 -238.600085)
		(end 372.080282 -238.549942)
		(width 0.0889)
		(layer "B.Cu")
		(net "CLK_25M_NSSC_CPU0_DP")
	)
	(arc
		(start 371.514878 -238.549942)
		(mid 371.32768 -238.600085)
		(end 371.140482 -238.549942)
		(width 0.0889)
		(layer "B.Cu")
		(net "CLK_25M_NSSC_CPU0_DP")
	)
	(arc
		(start 383.358136 -238.549942)
		(mid 383.075434 -238.474166)
		(end 382.792732 -238.549942)
		(width 0.0889)
		(layer "B.Cu")
		(net "CLK_25M_NSSC_CPU0_DP")
	)
	(arc
		(start 381.852932 -238.549942)
		(mid 381.665734 -238.600085)
		(end 381.478536 -238.549942)
		(width 0.0889)
		(layer "B.Cu")
		(net "CLK_25M_NSSC_CPU0_DP")
	)
	(arc
		(start 384.672332 -238.549942)
		(mid 384.485134 -238.600085)
		(end 384.297936 -238.549942)
		(width 0.0889)
		(layer "B.Cu")
		(net "CLK_25M_NSSC_CPU0_DP")
	)
	(arc
		(start 382.418336 -238.549942)
		(mid 382.135634 -238.474166)
		(end 381.852932 -238.549942)
		(width 0.0889)
		(layer "B.Cu")
		(net "CLK_25M_NSSC_CPU0_DP")
	)
	(arc
		(start 372.06555 -238.541306)
		(mid 371.789075 -238.473986)
		(end 371.514878 -238.549942)
		(width 0.0889)
		(layer "B.Cu")
		(net "CLK_25M_NSSC_CPU0_DP")
	)
	(arc
		(start 375.82475 -238.541306)
		(mid 375.548275 -238.473986)
		(end 375.274078 -238.549942)
		(width 0.0889)
		(layer "B.Cu")
		(net "CLK_25M_NSSC_CPU0_DP")
	)
	(arc
		(start 384.297936 -238.549942)
		(mid 384.015234 -238.474166)
		(end 383.732532 -238.549942)
		(width 0.0889)
		(layer "B.Cu")
		(net "CLK_25M_NSSC_CPU0_DP")
	)
	(arc
		(start 379.033278 -238.549942)
		(mid 378.84608 -238.600085)
		(end 378.658882 -238.549942)
		(width 0.0889)
		(layer "B.Cu")
		(net "CLK_25M_NSSC_CPU0_DP")
	)
	(arc
		(start 371.140482 -238.549942)
		(mid 370.579506 -238.547411)
		(end 370.29263 -239.029494)
		(width 0.0889)
		(layer "B.Cu")
		(net "CLK_25M_NSSC_CPU0_DP")
	)
	(arc
		(start 373.949722 -238.543846)
		(mid 373.67129 -238.474)
		(end 373.394478 -238.549942)
		(width 0.0889)
		(layer "B.Cu")
		(net "CLK_25M_NSSC_CPU0_DP")
	)
	(segment
		(start 341.470996 -135.825992)
		(end 347.798644 -140.053568)
		(width 0.13208)
		(layer "F.Cu")
		(net "CLK_25M_NSSC_CPU0_DN")
	)
	(segment
		(start 338.12988 -136.159494)
		(end 338.710778 -135.578596)
		(width 0.13208)
		(layer "F.Cu")
		(net "CLK_25M_NSSC_CPU0_DN")
	)
	(segment
		(start 371.501416 -156.784548)
		(end 372.483126 -157.766258)
		(width 0.13208)
		(layer "F.Cu")
		(net "CLK_25M_NSSC_CPU0_DN")
	)
	(segment
		(start 347.798644 -140.053822)
		(end 367.85423 -153.453592)
		(width 0.13208)
		(layer "F.Cu")
		(net "CLK_25M_NSSC_CPU0_DN")
	)
	(segment
		(start 369.44808 -238.76127)
		(end 369.44808 -238.225584)
		(width 0.13208)
		(layer "F.Cu")
		(net "CLK_25M_NSSC_CPU0_DN")
	)
	(segment
		(start 340.65464 -135.578596)
		(end 341.470996 -135.825992)
		(width 0.13208)
		(layer "F.Cu")
		(net "CLK_25M_NSSC_CPU0_DN")
	)
	(segment
		(start 373.44858 -160.581848)
		(end 373.75084 -160.884108)
		(width 0.13208)
		(layer "F.Cu")
		(net "CLK_25M_NSSC_CPU0_DN")
	)
	(segment
		(start 369.448334 -238.761524)
		(end 369.44808 -238.76127)
		(width 0.13208)
		(layer "F.Cu")
		(net "CLK_25M_NSSC_CPU0_DN")
	)
	(segment
		(start 338.12988 -136.769348)
		(end 338.12988 -136.159494)
		(width 0.13208)
		(layer "F.Cu")
		(net "CLK_25M_NSSC_CPU0_DN")
	)
	(segment
		(start 369.616482 -154.899868)
		(end 371.501416 -156.784802)
		(width 0.13208)
		(layer "F.Cu")
		(net "CLK_25M_NSSC_CPU0_DN")
	)
	(segment
		(start 347.798644 -140.053568)
		(end 347.798644 -140.053822)
		(width 0.13208)
		(layer "F.Cu")
		(net "CLK_25M_NSSC_CPU0_DN")
	)
	(segment
		(start 371.501416 -156.784802)
		(end 371.501416 -156.784548)
		(width 0.13208)
		(layer "F.Cu")
		(net "CLK_25M_NSSC_CPU0_DN")
	)
	(segment
		(start 338.710778 -135.578596)
		(end 340.65464 -135.578596)
		(width 0.13208)
		(layer "F.Cu")
		(net "CLK_25M_NSSC_CPU0_DN")
	)
	(segment
		(start 367.85423 -153.453592)
		(end 369.616482 -154.899868)
		(width 0.13208)
		(layer "F.Cu")
		(net "CLK_25M_NSSC_CPU0_DN")
	)
	(segment
		(start 337.845654 -137.053574)
		(end 338.12988 -136.769348)
		(width 0.13208)
		(layer "F.Cu")
		(net "CLK_25M_NSSC_CPU0_DN")
	)
	(segment
		(start 373.44858 -159.807148)
		(end 373.44858 -160.581848)
		(width 0.13208)
		(layer "F.Cu")
		(net "CLK_25M_NSSC_CPU0_DN")
	)
	(segment
		(start 372.483126 -157.766258)
		(end 373.44858 -159.807148)
		(width 0.13208)
		(layer "F.Cu")
		(net "CLK_25M_NSSC_CPU0_DN")
	)
	(segment
		(start 337.845654 -137.172446)
		(end 337.845654 -137.053574)
		(width 0.13208)
		(layer "F.Cu")
		(net "CLK_25M_NSSC_CPU0_DN")
	)
	(via
		(at 337.845654 -137.172446)
		(size 0.508)
		(drill 0.254)
		(layers "F.Cu" "B.Cu")
		(net "CLK_25M_NSSC_CPU0_DN")
	)
	(via
		(at 373.75084 -160.884108)
		(size 0.508)
		(drill 0.254)
		(layers "F.Cu" "B.Cu")
		(net "CLK_25M_NSSC_CPU0_DN")
	)
	(via
		(at 369.44808 -238.225584)
		(size 0.4572)
		(drill 0.2032)
		(layers "F.Cu" "B.Cu")
		(net "CLK_25M_NSSC_CPU0_DN")
	)
	(segment
		(start 378.578364 -238.723678)
		(end 378.563632 -238.715042)
		(width 0.0889)
		(layer "B.Cu")
		(net "CLK_25M_NSSC_CPU0_DN")
	)
	(segment
		(start 387.756146 -238.678466)
		(end 387.735826 -238.698786)
		(width 0.13208)
		(layer "B.Cu")
		(net "CLK_25M_NSSC_CPU0_DN")
	)
	(segment
		(start 369.635278 -239.528858)
		(end 369.446048 -239.426242)
		(width 0.0889)
		(layer "B.Cu")
		(net "CLK_25M_NSSC_CPU0_DN")
	)
	(segment
		(start 393.26439 -192.325244)
		(end 398.45742 -197.518274)
		(width 0.13208)
		(layer "B.Cu")
		(net "CLK_25M_NSSC_CPU0_DN")
	)
	(segment
		(start 370.483384 -239.030764)
		(end 370.483384 -239.049306)
		(width 0.0889)
		(layer "B.Cu")
		(net "CLK_25M_NSSC_CPU0_DN")
	)
	(segment
		(start 385.712716 -238.664242)
		(end 384.955288 -238.664242)
		(width 0.0889)
		(layer "B.Cu")
		(net "CLK_25M_NSSC_CPU0_DN")
	)
	(segment
		(start 393.26439 -192.32499)
		(end 393.26439 -192.325244)
		(width 0.13208)
		(layer "B.Cu")
		(net "CLK_25M_NSSC_CPU0_DN")
	)
	(segment
		(start 371.999764 -238.723678)
		(end 371.985032 -238.715042)
		(width 0.0889)
		(layer "B.Cu")
		(net "CLK_25M_NSSC_CPU0_DN")
	)
	(segment
		(start 369.446048 -239.426242)
		(end 369.28171 -239.26165)
		(width 0.0889)
		(layer "B.Cu")
		(net "CLK_25M_NSSC_CPU0_DN")
	)
	(segment
		(start 369.558316 -238.594646)
		(end 369.591082 -238.47298)
		(width 0.0889)
		(layer "B.Cu")
		(net "CLK_25M_NSSC_CPU0_DN")
	)
	(segment
		(start 375.758964 -238.723678)
		(end 375.744232 -238.715042)
		(width 0.0889)
		(layer "B.Cu")
		(net "CLK_25M_NSSC_CPU0_DN")
	)
	(segment
		(start 371.055392 -238.721138)
		(end 371.044978 -238.715042)
		(width 0.0889)
		(layer "B.Cu")
		(net "CLK_25M_NSSC_CPU0_DN")
	)
	(segment
		(start 374.819164 -238.723678)
		(end 374.804432 -238.715042)
		(width 0.0889)
		(layer "B.Cu")
		(net "CLK_25M_NSSC_CPU0_DN")
	)
	(segment
		(start 372.939564 -238.723678)
		(end 372.924832 -238.715042)
		(width 0.0889)
		(layer "B.Cu")
		(net "CLK_25M_NSSC_CPU0_DN")
	)
	(segment
		(start 398.45742 -229.460806)
		(end 398.10944 -230.300784)
		(width 0.13208)
		(layer "B.Cu")
		(net "CLK_25M_NSSC_CPU0_DN")
	)
	(segment
		(start 391.127996 -237.282228)
		(end 387.756146 -238.678466)
		(width 0.13208)
		(layer "B.Cu")
		(net "CLK_25M_NSSC_CPU0_DN")
	)
	(segment
		(start 373.75084 -160.884108)
		(end 373.44858 -161.186368)
		(width 0.13208)
		(layer "B.Cu")
		(net "CLK_25M_NSSC_CPU0_DN")
	)
	(segment
		(start 373.44858 -161.92754)
		(end 374.630442 -164.780468)
		(width 0.13208)
		(layer "B.Cu")
		(net "CLK_25M_NSSC_CPU0_DN")
	)
	(segment
		(start 387.735826 -238.698786)
		(end 385.769358 -238.698786)
		(width 0.13208)
		(layer "B.Cu")
		(net "CLK_25M_NSSC_CPU0_DN")
	)
	(segment
		(start 378.005594 -171.401232)
		(end 379.74905 -174.309786)
		(width 0.13208)
		(layer "B.Cu")
		(net "CLK_25M_NSSC_CPU0_DN")
	)
	(segment
		(start 376.694446 -238.721138)
		(end 376.684032 -238.715042)
		(width 0.0889)
		(layer "B.Cu")
		(net "CLK_25M_NSSC_CPU0_DN")
	)
	(segment
		(start 369.28171 -239.26165)
		(end 369.28171 -238.81588)
		(width 0.0889)
		(layer "B.Cu")
		(net "CLK_25M_NSSC_CPU0_DN")
	)
	(segment
		(start 373.44858 -161.186368)
		(end 373.44858 -161.92754)
		(width 0.13208)
		(layer "B.Cu")
		(net "CLK_25M_NSSC_CPU0_DN")
	)
	(segment
		(start 374.630442 -164.780468)
		(end 377.397772 -169.397172)
		(width 0.13208)
		(layer "B.Cu")
		(net "CLK_25M_NSSC_CPU0_DN")
	)
	(segment
		(start 369.42776 -238.66983)
		(end 369.558316 -238.594646)
		(width 0.0889)
		(layer "B.Cu")
		(net "CLK_25M_NSSC_CPU0_DN")
	)
	(segment
		(start 369.591082 -238.47298)
		(end 369.44808 -238.225584)
		(width 0.0889)
		(layer "B.Cu")
		(net "CLK_25M_NSSC_CPU0_DN")
	)
	(segment
		(start 369.28171 -238.81588)
		(end 369.42776 -238.66983)
		(width 0.0889)
		(layer "B.Cu")
		(net "CLK_25M_NSSC_CPU0_DN")
	)
	(segment
		(start 338.022184 -136.995916)
		(end 338.022184 -136.479534)
		(width 0.13208)
		(layer "B.Cu")
		(net "CLK_25M_NSSC_CPU0_DN")
	)
	(segment
		(start 398.45742 -197.518274)
		(end 398.45742 -229.460806)
		(width 0.13208)
		(layer "B.Cu")
		(net "CLK_25M_NSSC_CPU0_DN")
	)
	(segment
		(start 398.10944 -230.300784)
		(end 391.127996 -237.282228)
		(width 0.13208)
		(layer "B.Cu")
		(net "CLK_25M_NSSC_CPU0_DN")
	)
	(segment
		(start 385.769358 -238.698786)
		(end 385.74726 -238.698786)
		(width 0.0889)
		(layer "B.Cu")
		(net "CLK_25M_NSSC_CPU0_DN")
	)
	(segment
		(start 377.397772 -169.397172)
		(end 378.005594 -171.401232)
		(width 0.13208)
		(layer "B.Cu")
		(net "CLK_25M_NSSC_CPU0_DN")
	)
	(segment
		(start 379.74905 -174.309786)
		(end 390.082024 -184.643014)
		(width 0.13208)
		(layer "B.Cu")
		(net "CLK_25M_NSSC_CPU0_DN")
	)
	(segment
		(start 337.845654 -137.172446)
		(end 338.022184 -136.995916)
		(width 0.13208)
		(layer "B.Cu")
		(net "CLK_25M_NSSC_CPU0_DN")
	)
	(segment
		(start 379.518164 -238.723678)
		(end 379.503432 -238.715042)
		(width 0.0889)
		(layer "B.Cu")
		(net "CLK_25M_NSSC_CPU0_DN")
	)
	(segment
		(start 385.74726 -238.698786)
		(end 385.712716 -238.664242)
		(width 0.0889)
		(layer "B.Cu")
		(net "CLK_25M_NSSC_CPU0_DN")
	)
	(segment
		(start 390.082024 -184.643014)
		(end 393.26439 -192.32499)
		(width 0.13208)
		(layer "B.Cu")
		(net "CLK_25M_NSSC_CPU0_DN")
	)
	(segment
		(start 377.633992 -238.721138)
		(end 377.623578 -238.715042)
		(width 0.0889)
		(layer "B.Cu")
		(net "CLK_25M_NSSC_CPU0_DN")
	)
	(arc
		(start 381.383032 -238.715042)
		(mid 381.195834 -238.664899)
		(end 381.008636 -238.715042)
		(width 0.0889)
		(layer "B.Cu")
		(net "CLK_25M_NSSC_CPU0_DN")
	)
	(arc
		(start 377.623578 -238.715042)
		(mid 377.43638 -238.664899)
		(end 377.249182 -238.715042)
		(width 0.0889)
		(layer "B.Cu")
		(net "CLK_25M_NSSC_CPU0_DN")
	)
	(arc
		(start 373.490236 -238.715042)
		(mid 373.216037 -238.790877)
		(end 372.939564 -238.723678)
		(width 0.0889)
		(layer "B.Cu")
		(net "CLK_25M_NSSC_CPU0_DN")
	)
	(arc
		(start 375.744232 -238.715042)
		(mid 375.557034 -238.664899)
		(end 375.369836 -238.715042)
		(width 0.0889)
		(layer "B.Cu")
		(net "CLK_25M_NSSC_CPU0_DN")
	)
	(arc
		(start 384.202432 -238.715042)
		(mid 384.015234 -238.664899)
		(end 383.828036 -238.715042)
		(width 0.0889)
		(layer "B.Cu")
		(net "CLK_25M_NSSC_CPU0_DN")
	)
	(arc
		(start 381.948436 -238.715042)
		(mid 381.665734 -238.790818)
		(end 381.383032 -238.715042)
		(width 0.0889)
		(layer "B.Cu")
		(net "CLK_25M_NSSC_CPU0_DN")
	)
	(arc
		(start 377.249182 -238.715042)
		(mid 376.972623 -238.790785)
		(end 376.694446 -238.721138)
		(width 0.0889)
		(layer "B.Cu")
		(net "CLK_25M_NSSC_CPU0_DN")
	)
	(arc
		(start 379.503432 -238.715042)
		(mid 379.316234 -238.664899)
		(end 379.129036 -238.715042)
		(width 0.0889)
		(layer "B.Cu")
		(net "CLK_25M_NSSC_CPU0_DN")
	)
	(arc
		(start 373.864632 -238.715042)
		(mid 373.677434 -238.664899)
		(end 373.490236 -238.715042)
		(width 0.0889)
		(layer "B.Cu")
		(net "CLK_25M_NSSC_CPU0_DN")
	)
	(arc
		(start 382.888236 -238.715042)
		(mid 382.605534 -238.790818)
		(end 382.322832 -238.715042)
		(width 0.0889)
		(layer "B.Cu")
		(net "CLK_25M_NSSC_CPU0_DN")
	)
	(arc
		(start 374.430036 -238.715042)
		(mid 374.147334 -238.790818)
		(end 373.864632 -238.715042)
		(width 0.0889)
		(layer "B.Cu")
		(net "CLK_25M_NSSC_CPU0_DN")
	)
	(arc
		(start 384.92303 -238.665766)
		(mid 384.842715 -238.681853)
		(end 384.767836 -238.715042)
		(width 0.0889)
		(layer "B.Cu")
		(net "CLK_25M_NSSC_CPU0_DN")
	)
	(arc
		(start 376.684032 -238.715042)
		(mid 376.496834 -238.664899)
		(end 376.309636 -238.715042)
		(width 0.0889)
		(layer "B.Cu")
		(net "CLK_25M_NSSC_CPU0_DN")
	)
	(arc
		(start 371.985032 -238.715042)
		(mid 371.797834 -238.664899)
		(end 371.610636 -238.715042)
		(width 0.0889)
		(layer "B.Cu")
		(net "CLK_25M_NSSC_CPU0_DN")
	)
	(arc
		(start 380.443232 -238.715042)
		(mid 380.256034 -238.664899)
		(end 380.068836 -238.715042)
		(width 0.0889)
		(layer "B.Cu")
		(net "CLK_25M_NSSC_CPU0_DN")
	)
	(arc
		(start 372.550436 -238.715042)
		(mid 372.276237 -238.790877)
		(end 371.999764 -238.723678)
		(width 0.0889)
		(layer "B.Cu")
		(net "CLK_25M_NSSC_CPU0_DN")
	)
	(arc
		(start 382.322832 -238.715042)
		(mid 382.135634 -238.664899)
		(end 381.948436 -238.715042)
		(width 0.0889)
		(layer "B.Cu")
		(net "CLK_25M_NSSC_CPU0_DN")
	)
	(arc
		(start 374.804432 -238.715042)
		(mid 374.617234 -238.664899)
		(end 374.430036 -238.715042)
		(width 0.0889)
		(layer "B.Cu")
		(net "CLK_25M_NSSC_CPU0_DN")
	)
	(arc
		(start 379.129036 -238.715042)
		(mid 378.854837 -238.790877)
		(end 378.578364 -238.723678)
		(width 0.0889)
		(layer "B.Cu")
		(net "CLK_25M_NSSC_CPU0_DN")
	)
	(arc
		(start 381.008636 -238.715042)
		(mid 380.725934 -238.790818)
		(end 380.443232 -238.715042)
		(width 0.0889)
		(layer "B.Cu")
		(net "CLK_25M_NSSC_CPU0_DN")
	)
	(arc
		(start 380.068836 -238.715042)
		(mid 379.794637 -238.790877)
		(end 379.518164 -238.723678)
		(width 0.0889)
		(layer "B.Cu")
		(net "CLK_25M_NSSC_CPU0_DN")
	)
	(arc
		(start 370.483384 -239.049306)
		(mid 370.196329 -239.531393)
		(end 369.635278 -239.528858)
		(width 0.0889)
		(layer "B.Cu")
		(net "CLK_25M_NSSC_CPU0_DN")
	)
	(arc
		(start 383.828036 -238.715042)
		(mid 383.545334 -238.790818)
		(end 383.262632 -238.715042)
		(width 0.0889)
		(layer "B.Cu")
		(net "CLK_25M_NSSC_CPU0_DN")
	)
	(arc
		(start 383.262632 -238.715042)
		(mid 383.075434 -238.664899)
		(end 382.888236 -238.715042)
		(width 0.0889)
		(layer "B.Cu")
		(net "CLK_25M_NSSC_CPU0_DN")
	)
	(arc
		(start 376.309636 -238.715042)
		(mid 376.035437 -238.790877)
		(end 375.758964 -238.723678)
		(width 0.0889)
		(layer "B.Cu")
		(net "CLK_25M_NSSC_CPU0_DN")
	)
	(arc
		(start 371.044978 -238.715042)
		(mid 370.674255 -238.71295)
		(end 370.483384 -239.030764)
		(width 0.0889)
		(layer "B.Cu")
		(net "CLK_25M_NSSC_CPU0_DN")
	)
	(arc
		(start 372.924832 -238.715042)
		(mid 372.737634 -238.664899)
		(end 372.550436 -238.715042)
		(width 0.0889)
		(layer "B.Cu")
		(net "CLK_25M_NSSC_CPU0_DN")
	)
	(arc
		(start 371.610636 -238.715042)
		(mid 371.333823 -238.790912)
		(end 371.055392 -238.721138)
		(width 0.0889)
		(layer "B.Cu")
		(net "CLK_25M_NSSC_CPU0_DN")
	)
	(arc
		(start 384.767836 -238.715042)
		(mid 384.485134 -238.790818)
		(end 384.202432 -238.715042)
		(width 0.0889)
		(layer "B.Cu")
		(net "CLK_25M_NSSC_CPU0_DN")
	)
	(arc
		(start 378.563632 -238.715042)
		(mid 378.376434 -238.664899)
		(end 378.189236 -238.715042)
		(width 0.0889)
		(layer "B.Cu")
		(net "CLK_25M_NSSC_CPU0_DN")
	)
	(arc
		(start 378.189236 -238.715042)
		(mid 377.912423 -238.790912)
		(end 377.633992 -238.721138)
		(width 0.0889)
		(layer "B.Cu")
		(net "CLK_25M_NSSC_CPU0_DN")
	)
	(arc
		(start 375.369836 -238.715042)
		(mid 375.095637 -238.790877)
		(end 374.819164 -238.723678)
		(width 0.0889)
		(layer "B.Cu")
		(net "CLK_25M_NSSC_CPU0_DN")
	)
	(arc
		(start 384.955288 -238.664242)
		(mid 384.939143 -238.664656)
		(end 384.92303 -238.665766)
		(width 0.0889)
		(layer "B.Cu")
		(net "CLK_25M_NSSC_CPU0_DN")
	)
	(segment
		(start 251.083318 -105.483152)
		(end 251.083318 -107.442762)
		(width 0.13208)
		(layer "F.Cu")
		(net "CLK_25M_CK440_ISCLK_REF_DP")
	)
	(segment
		(start 251.083318 -107.442762)
		(end 250.733306 -107.792774)
		(width 0.13208)
		(layer "F.Cu")
		(net "CLK_25M_CK440_ISCLK_REF_DP")
	)
	(segment
		(start 252.553216 -104.013254)
		(end 251.083318 -105.483152)
		(width 0.13208)
		(layer "F.Cu")
		(net "CLK_25M_CK440_ISCLK_REF_DP")
	)
	(segment
		(start 252.553216 -103.807514)
		(end 252.553216 -104.013254)
		(width 0.13208)
		(layer "F.Cu")
		(net "CLK_25M_CK440_ISCLK_REF_DP")
	)
	(segment
		(start 252.43282 -103.687118)
		(end 252.553216 -103.807514)
		(width 0.13208)
		(layer "F.Cu")
		(net "CLK_25M_CK440_ISCLK_REF_DP")
	)
	(segment
		(start 252.43282 -103.438198)
		(end 252.43282 -103.687118)
		(width 0.13208)
		(layer "F.Cu")
		(net "CLK_25M_CK440_ISCLK_REF_DP")
	)
	(segment
		(start 252.812296 -103.78059)
		(end 252.812296 -104.120696)
		(width 0.13208)
		(layer "F.Cu")
		(net "CLK_25M_CK440_ISCLK_REF_DN")
	)
	(segment
		(start 252.812296 -104.120696)
		(end 251.342398 -105.590594)
		(width 0.13208)
		(layer "F.Cu")
		(net "CLK_25M_CK440_ISCLK_REF_DN")
	)
	(segment
		(start 251.342398 -107.385612)
		(end 251.74956 -107.792774)
		(width 0.13208)
		(layer "F.Cu")
		(net "CLK_25M_CK440_ISCLK_REF_DN")
	)
	(segment
		(start 251.342398 -105.590594)
		(end 251.342398 -107.385612)
		(width 0.13208)
		(layer "F.Cu")
		(net "CLK_25M_CK440_ISCLK_REF_DN")
	)
	(segment
		(start 252.932692 -103.438198)
		(end 252.932692 -103.660194)
		(width 0.13208)
		(layer "F.Cu")
		(net "CLK_25M_CK440_ISCLK_REF_DN")
	)
	(segment
		(start 252.932692 -103.660194)
		(end 252.812296 -103.78059)
		(width 0.13208)
		(layer "F.Cu")
		(net "CLK_25M_CK440_ISCLK_REF_DN")
	)
	(segment
		(start 240.086388 -110.596934)
		(end 239.784128 -110.294674)
		(width 0.13208)
		(layer "F.Cu")
		(net "CLK_25M_CK440_CPU1_R_DP")
	)
	(segment
		(start 240.908078 -110.240572)
		(end 240.551716 -110.596934)
		(width 0.13208)
		(layer "F.Cu")
		(net "CLK_25M_CK440_CPU1_R_DP")
	)
	(segment
		(start 240.551716 -110.596934)
		(end 240.086388 -110.596934)
		(width 0.13208)
		(layer "F.Cu")
		(net "CLK_25M_CK440_CPU1_R_DP")
	)
	(via
		(at 234.411266 -134.258304)
		(size 0.508)
		(drill 0.254)
		(layers "F.Cu" "B.Cu")
		(net "CLK_25M_CK440_CPU1_R_DP")
	)
	(via
		(at 239.784128 -110.294674)
		(size 0.508)
		(drill 0.254)
		(layers "F.Cu" "B.Cu")
		(net "CLK_25M_CK440_CPU1_R_DP")
	)
	(segment
		(start 235.163106 -134.557008)
		(end 235.67136 -134.048754)
		(width 0.13208)
		(layer "B.Cu")
		(net "CLK_25M_CK440_CPU1_R_DP")
	)
	(segment
		(start 235.67136 -134.048754)
		(end 235.782104 -134.048754)
		(width 0.13208)
		(layer "B.Cu")
		(net "CLK_25M_CK440_CPU1_R_DP")
	)
	(segment
		(start 234.70997 -134.557008)
		(end 235.163106 -134.557008)
		(width 0.13208)
		(layer "B.Cu")
		(net "CLK_25M_CK440_CPU1_R_DP")
	)
	(segment
		(start 234.411266 -134.258304)
		(end 234.70997 -134.557008)
		(width 0.13208)
		(layer "B.Cu")
		(net "CLK_25M_CK440_CPU1_R_DP")
	)
	(segment
		(start 238.764064 -111.888778)
		(end 239.816894 -112.941608)
		(width 0.14732)
		(layer "In2.Cu")
		(net "CLK_25M_CK440_CPU1_R_DP")
	)
	(segment
		(start 240.654332 -118.261384)
		(end 238.60506 -120.310656)
		(width 0.14732)
		(layer "In2.Cu")
		(net "CLK_25M_CK440_CPU1_R_DP")
	)
	(segment
		(start 239.167162 -110.589314)
		(end 238.764064 -110.992412)
		(width 0.14732)
		(layer "In2.Cu")
		(net "CLK_25M_CK440_CPU1_R_DP")
	)
	(segment
		(start 237.446312 -128.78816)
		(end 235.62056 -133.195822)
		(width 0.14732)
		(layer "In2.Cu")
		(net "CLK_25M_CK440_CPU1_R_DP")
	)
	(segment
		(start 239.489488 -110.589314)
		(end 239.167162 -110.589314)
		(width 0.14732)
		(layer "In2.Cu")
		(net "CLK_25M_CK440_CPU1_R_DP")
	)
	(segment
		(start 235.62056 -133.195822)
		(end 235.62056 -133.785356)
		(width 0.14732)
		(layer "In2.Cu")
		(net "CLK_25M_CK440_CPU1_R_DP")
	)
	(segment
		(start 237.446312 -123.108212)
		(end 237.446312 -128.78816)
		(width 0.14732)
		(layer "In2.Cu")
		(net "CLK_25M_CK440_CPU1_R_DP")
	)
	(segment
		(start 241.161062 -116.186458)
		(end 241.161062 -116.768118)
		(width 0.14732)
		(layer "In2.Cu")
		(net "CLK_25M_CK440_CPU1_R_DP")
	)
	(segment
		(start 239.784128 -110.294674)
		(end 239.489488 -110.589314)
		(width 0.14732)
		(layer "In2.Cu")
		(net "CLK_25M_CK440_CPU1_R_DP")
	)
	(segment
		(start 235.62056 -133.785356)
		(end 234.852972 -134.552944)
		(width 0.14732)
		(layer "In2.Cu")
		(net "CLK_25M_CK440_CPU1_R_DP")
	)
	(segment
		(start 241.161062 -116.768118)
		(end 241.057684 -117.287802)
		(width 0.14732)
		(layer "In2.Cu")
		(net "CLK_25M_CK440_CPU1_R_DP")
	)
	(segment
		(start 238.764064 -110.992412)
		(end 238.764064 -111.888778)
		(width 0.14732)
		(layer "In2.Cu")
		(net "CLK_25M_CK440_CPU1_R_DP")
	)
	(segment
		(start 241.057684 -117.287802)
		(end 240.654332 -118.261384)
		(width 0.14732)
		(layer "In2.Cu")
		(net "CLK_25M_CK440_CPU1_R_DP")
	)
	(segment
		(start 234.852972 -134.552944)
		(end 234.705906 -134.552944)
		(width 0.14732)
		(layer "In2.Cu")
		(net "CLK_25M_CK440_CPU1_R_DP")
	)
	(segment
		(start 239.816894 -112.941608)
		(end 241.161062 -116.186458)
		(width 0.14732)
		(layer "In2.Cu")
		(net "CLK_25M_CK440_CPU1_R_DP")
	)
	(segment
		(start 238.60506 -120.310656)
		(end 237.446312 -123.108212)
		(width 0.14732)
		(layer "In2.Cu")
		(net "CLK_25M_CK440_CPU1_R_DP")
	)
	(segment
		(start 234.705906 -134.552944)
		(end 234.411266 -134.258304)
		(width 0.14732)
		(layer "In2.Cu")
		(net "CLK_25M_CK440_CPU1_R_DP")
	)
	(segment
		(start 240.532158 -110.856014)
		(end 240.086388 -110.856014)
		(width 0.13208)
		(layer "F.Cu")
		(net "CLK_25M_CK440_CPU1_R_DN")
	)
	(segment
		(start 240.88852 -111.212376)
		(end 240.532158 -110.856014)
		(width 0.13208)
		(layer "F.Cu")
		(net "CLK_25M_CK440_CPU1_R_DN")
	)
	(segment
		(start 240.086388 -110.856014)
		(end 239.784128 -111.158274)
		(width 0.13208)
		(layer "F.Cu")
		(net "CLK_25M_CK440_CPU1_R_DN")
	)
	(via
		(at 234.411266 -135.121904)
		(size 0.508)
		(drill 0.254)
		(layers "F.Cu" "B.Cu")
		(net "CLK_25M_CK440_CPU1_R_DN")
	)
	(via
		(at 239.784128 -111.158274)
		(size 0.508)
		(drill 0.254)
		(layers "F.Cu" "B.Cu")
		(net "CLK_25M_CK440_CPU1_R_DN")
	)
	(segment
		(start 234.714542 -134.818628)
		(end 235.128054 -134.818628)
		(width 0.13208)
		(layer "B.Cu")
		(net "CLK_25M_CK440_CPU1_R_DN")
	)
	(segment
		(start 235.128054 -134.818628)
		(end 235.710984 -135.401558)
		(width 0.13208)
		(layer "B.Cu")
		(net "CLK_25M_CK440_CPU1_R_DN")
	)
	(segment
		(start 235.710984 -135.401558)
		(end 235.801662 -135.401558)
		(width 0.13208)
		(layer "B.Cu")
		(net "CLK_25M_CK440_CPU1_R_DN")
	)
	(segment
		(start 234.411266 -135.121904)
		(end 234.714542 -134.818628)
		(width 0.13208)
		(layer "B.Cu")
		(net "CLK_25M_CK440_CPU1_R_DN")
	)
	(segment
		(start 239.038384 -111.774986)
		(end 240.049558 -112.78616)
		(width 0.14732)
		(layer "In2.Cu")
		(net "CLK_25M_CK440_CPU1_R_DN")
	)
	(segment
		(start 240.886996 -118.416832)
		(end 238.837724 -120.466104)
		(width 0.14732)
		(layer "In2.Cu")
		(net "CLK_25M_CK440_CPU1_R_DN")
	)
	(segment
		(start 241.32159 -117.367812)
		(end 240.886996 -118.416832)
		(width 0.14732)
		(layer "In2.Cu")
		(net "CLK_25M_CK440_CPU1_R_DN")
	)
	(segment
		(start 234.966764 -134.827264)
		(end 234.705906 -134.827264)
		(width 0.14732)
		(layer "In2.Cu")
		(net "CLK_25M_CK440_CPU1_R_DN")
	)
	(segment
		(start 241.435382 -116.795296)
		(end 241.32159 -117.367812)
		(width 0.14732)
		(layer "In2.Cu")
		(net "CLK_25M_CK440_CPU1_R_DN")
	)
	(segment
		(start 234.705906 -134.827264)
		(end 234.411266 -135.121904)
		(width 0.14732)
		(layer "In2.Cu")
		(net "CLK_25M_CK440_CPU1_R_DN")
	)
	(segment
		(start 240.049558 -112.78616)
		(end 241.435382 -116.131848)
		(width 0.14732)
		(layer "In2.Cu")
		(net "CLK_25M_CK440_CPU1_R_DN")
	)
	(segment
		(start 238.837724 -120.466104)
		(end 237.720632 -123.162822)
		(width 0.14732)
		(layer "In2.Cu")
		(net "CLK_25M_CK440_CPU1_R_DN")
	)
	(segment
		(start 239.280954 -110.863634)
		(end 239.038384 -111.106204)
		(width 0.14732)
		(layer "In2.Cu")
		(net "CLK_25M_CK440_CPU1_R_DN")
	)
	(segment
		(start 235.89488 -133.250432)
		(end 235.89488 -133.899148)
		(width 0.14732)
		(layer "In2.Cu")
		(net "CLK_25M_CK440_CPU1_R_DN")
	)
	(segment
		(start 237.720632 -123.162822)
		(end 237.720632 -128.84277)
		(width 0.14732)
		(layer "In2.Cu")
		(net "CLK_25M_CK440_CPU1_R_DN")
	)
	(segment
		(start 235.89488 -133.899148)
		(end 234.966764 -134.827264)
		(width 0.14732)
		(layer "In2.Cu")
		(net "CLK_25M_CK440_CPU1_R_DN")
	)
	(segment
		(start 241.435382 -116.131848)
		(end 241.435382 -116.795296)
		(width 0.14732)
		(layer "In2.Cu")
		(net "CLK_25M_CK440_CPU1_R_DN")
	)
	(segment
		(start 239.784128 -111.158274)
		(end 239.489488 -110.863634)
		(width 0.14732)
		(layer "In2.Cu")
		(net "CLK_25M_CK440_CPU1_R_DN")
	)
	(segment
		(start 239.489488 -110.863634)
		(end 239.280954 -110.863634)
		(width 0.14732)
		(layer "In2.Cu")
		(net "CLK_25M_CK440_CPU1_R_DN")
	)
	(segment
		(start 239.038384 -111.106204)
		(end 239.038384 -111.774986)
		(width 0.14732)
		(layer "In2.Cu")
		(net "CLK_25M_CK440_CPU1_R_DN")
	)
	(segment
		(start 237.720632 -128.84277)
		(end 235.89488 -133.250432)
		(width 0.14732)
		(layer "In2.Cu")
		(net "CLK_25M_CK440_CPU1_R_DN")
	)
	(segment
		(start 247.597168 -105.016046)
		(end 247.596914 -105.016046)
		(width 0.13208)
		(layer "F.Cu")
		(net "CLK_25M_CK440_CPU1_DP")
	)
	(segment
		(start 247.596914 -105.016046)
		(end 246.955564 -105.542334)
		(width 0.13208)
		(layer "F.Cu")
		(net "CLK_25M_CK440_CPU1_DP")
	)
	(segment
		(start 251.327158 -101.933756)
		(end 251.173996 -101.997002)
		(width 0.13208)
		(layer "F.Cu")
		(net "CLK_25M_CK440_CPU1_DP")
	)
	(segment
		(start 246.409718 -106.86034)
		(end 245.200932 -108.068872)
		(width 0.13208)
		(layer "F.Cu")
		(net "CLK_25M_CK440_CPU1_DP")
	)
	(segment
		(start 251.173996 -101.997002)
		(end 250.710446 -102.460806)
		(width 0.13208)
		(layer "F.Cu")
		(net "CLK_25M_CK440_CPU1_DP")
	)
	(segment
		(start 251.495306 -101.933756)
		(end 251.327158 -101.933756)
		(width 0.13208)
		(layer "F.Cu")
		(net "CLK_25M_CK440_CPU1_DP")
	)
	(segment
		(start 242.956842 -110.312962)
		(end 242.673124 -110.596934)
		(width 0.13208)
		(layer "F.Cu")
		(net "CLK_25M_CK440_CPU1_DP")
	)
	(segment
		(start 250.710446 -102.460806)
		(end 247.597168 -105.016046)
		(width 0.13208)
		(layer "F.Cu")
		(net "CLK_25M_CK440_CPU1_DP")
	)
	(segment
		(start 251.615956 -101.813106)
		(end 251.495306 -101.933756)
		(width 0.13208)
		(layer "F.Cu")
		(net "CLK_25M_CK440_CPU1_DP")
	)
	(segment
		(start 251.807726 -101.813106)
		(end 251.615956 -101.813106)
		(width 0.13208)
		(layer "F.Cu")
		(net "CLK_25M_CK440_CPU1_DP")
	)
	(segment
		(start 242.06454 -110.596934)
		(end 241.708178 -110.240572)
		(width 0.13208)
		(layer "F.Cu")
		(net "CLK_25M_CK440_CPU1_DP")
	)
	(segment
		(start 242.673124 -110.596934)
		(end 242.06454 -110.596934)
		(width 0.13208)
		(layer "F.Cu")
		(net "CLK_25M_CK440_CPU1_DP")
	)
	(segment
		(start 245.200932 -108.068872)
		(end 242.956842 -110.312962)
		(width 0.13208)
		(layer "F.Cu")
		(net "CLK_25M_CK440_CPU1_DP")
	)
	(segment
		(start 246.955564 -105.542334)
		(end 246.409718 -106.86034)
		(width 0.13208)
		(layer "F.Cu")
		(net "CLK_25M_CK440_CPU1_DP")
	)
	(segment
		(start 242.780566 -110.856014)
		(end 242.044982 -110.856014)
		(width 0.13208)
		(layer "F.Cu")
		(net "CLK_25M_CK440_CPU1_DN")
	)
	(segment
		(start 247.170194 -105.701592)
		(end 246.629428 -107.007152)
		(width 0.13208)
		(layer "F.Cu")
		(net "CLK_25M_CK440_CPU1_DN")
	)
	(segment
		(start 251.350018 -102.204774)
		(end 251.320808 -102.216966)
		(width 0.13208)
		(layer "F.Cu")
		(net "CLK_25M_CK440_CPU1_DN")
	)
	(segment
		(start 250.884944 -102.653084)
		(end 247.170194 -105.701592)
		(width 0.13208)
		(layer "F.Cu")
		(net "CLK_25M_CK440_CPU1_DN")
	)
	(segment
		(start 251.610622 -102.313232)
		(end 251.490226 -102.192836)
		(width 0.13208)
		(layer "F.Cu")
		(net "CLK_25M_CK440_CPU1_DN")
	)
	(segment
		(start 251.37872 -102.192836)
		(end 251.350018 -102.204774)
		(width 0.13208)
		(layer "F.Cu")
		(net "CLK_25M_CK440_CPU1_DN")
	)
	(segment
		(start 242.044982 -110.856014)
		(end 241.68862 -111.212376)
		(width 0.13208)
		(layer "F.Cu")
		(net "CLK_25M_CK440_CPU1_DN")
	)
	(segment
		(start 246.629428 -107.007152)
		(end 242.780566 -110.856014)
		(width 0.13208)
		(layer "F.Cu")
		(net "CLK_25M_CK440_CPU1_DN")
	)
	(segment
		(start 251.807726 -102.313232)
		(end 251.610622 -102.313232)
		(width 0.13208)
		(layer "F.Cu")
		(net "CLK_25M_CK440_CPU1_DN")
	)
	(segment
		(start 251.490226 -102.192836)
		(end 251.37872 -102.192836)
		(width 0.13208)
		(layer "F.Cu")
		(net "CLK_25M_CK440_CPU1_DN")
	)
	(segment
		(start 251.320808 -102.216966)
		(end 250.884944 -102.653084)
		(width 0.13208)
		(layer "F.Cu")
		(net "CLK_25M_CK440_CPU1_DN")
	)
	(segment
		(start 240.558574 -108.128054)
		(end 239.331246 -108.128054)
		(width 0.13208)
		(layer "F.Cu")
		(net "CLK_25M_CK440_CPU0_R_DP")
	)
	(segment
		(start 240.914936 -107.771692)
		(end 240.558574 -108.128054)
		(width 0.13208)
		(layer "F.Cu")
		(net "CLK_25M_CK440_CPU0_R_DP")
	)
	(segment
		(start 239.331246 -108.128054)
		(end 239.028986 -107.825794)
		(width 0.13208)
		(layer "F.Cu")
		(net "CLK_25M_CK440_CPU0_R_DP")
	)
	(via
		(at 239.028986 -107.825794)
		(size 0.508)
		(drill 0.254)
		(layers "F.Cu" "B.Cu")
		(net "CLK_25M_CK440_CPU0_R_DP")
	)
	(segment
		(start 336.502248 -137.219182)
		(end 335.42224 -137.219182)
		(width 0.13208)
		(layer "B.Cu")
		(net "CLK_25M_CK440_CPU0_R_DP")
	)
	(segment
		(start 238.46282 -107.906058)
		(end 238.506508 -108.011468)
		(width 0.13208)
		(layer "B.Cu")
		(net "CLK_25M_CK440_CPU0_R_DP")
	)
	(segment
		(start 247.379744 -111.890048)
		(end 246.681498 -111.191802)
		(width 0.13208)
		(layer "B.Cu")
		(net "CLK_25M_CK440_CPU0_R_DP")
	)
	(segment
		(start 330.8477 -135.324342)
		(end 325.22033 -129.696972)
		(width 0.13208)
		(layer "B.Cu")
		(net "CLK_25M_CK440_CPU0_R_DP")
	)
	(segment
		(start 242.899184 -107.58551)
		(end 242.629436 -107.315762)
		(width 0.13208)
		(layer "B.Cu")
		(net "CLK_25M_CK440_CPU0_R_DP")
	)
	(segment
		(start 238.665512 -106.8705)
		(end 238.46282 -107.073192)
		(width 0.13208)
		(layer "B.Cu")
		(net "CLK_25M_CK440_CPU0_R_DP")
	)
	(segment
		(start 238.623094 -108.128054)
		(end 238.726726 -108.128054)
		(width 0.13208)
		(layer "B.Cu")
		(net "CLK_25M_CK440_CPU0_R_DP")
	)
	(segment
		(start 243.075206 -107.58551)
		(end 242.899184 -107.58551)
		(width 0.13208)
		(layer "B.Cu")
		(net "CLK_25M_CK440_CPU0_R_DP")
	)
	(segment
		(start 317.950596 -126.685802)
		(end 254.642366 -114.09299)
		(width 0.13208)
		(layer "B.Cu")
		(net "CLK_25M_CK440_CPU0_R_DP")
	)
	(segment
		(start 240.552986 -106.8705)
		(end 240.428526 -106.99496)
		(width 0.13208)
		(layer "B.Cu")
		(net "CLK_25M_CK440_CPU0_R_DP")
	)
	(segment
		(start 246.235728 -110.746032)
		(end 245.966488 -110.476792)
		(width 0.13208)
		(layer "B.Cu")
		(net "CLK_25M_CK440_CPU0_R_DP")
	)
	(segment
		(start 244.059456 -108.745782)
		(end 244.059456 -108.56976)
		(width 0.13208)
		(layer "B.Cu")
		(net "CLK_25M_CK440_CPU0_R_DP")
	)
	(segment
		(start 244.505226 -109.01553)
		(end 244.329204 -109.01553)
		(width 0.13208)
		(layer "B.Cu")
		(net "CLK_25M_CK440_CPU0_R_DP")
	)
	(segment
		(start 240.047526 -106.99496)
		(end 239.923066 -106.8705)
		(width 0.13208)
		(layer "B.Cu")
		(net "CLK_25M_CK440_CPU0_R_DP")
	)
	(segment
		(start 245.044214 -109.73054)
		(end 244.774466 -109.460792)
		(width 0.13208)
		(layer "B.Cu")
		(net "CLK_25M_CK440_CPU0_R_DP")
	)
	(segment
		(start 245.790466 -110.476792)
		(end 245.520718 -110.207044)
		(width 0.13208)
		(layer "B.Cu")
		(net "CLK_25M_CK440_CPU0_R_DP")
	)
	(segment
		(start 238.506508 -108.011468)
		(end 238.623094 -108.128054)
		(width 0.13208)
		(layer "B.Cu")
		(net "CLK_25M_CK440_CPU0_R_DP")
	)
	(segment
		(start 243.614194 -108.30052)
		(end 243.344446 -108.030772)
		(width 0.13208)
		(layer "B.Cu")
		(net "CLK_25M_CK440_CPU0_R_DP")
	)
	(segment
		(start 337.115404 -137.832338)
		(end 336.502248 -137.219182)
		(width 0.13208)
		(layer "B.Cu")
		(net "CLK_25M_CK440_CPU0_R_DP")
	)
	(segment
		(start 335.42224 -137.219182)
		(end 330.8477 -135.324342)
		(width 0.13208)
		(layer "B.Cu")
		(net "CLK_25M_CK440_CPU0_R_DP")
	)
	(segment
		(start 243.344446 -108.030772)
		(end 243.344446 -107.85475)
		(width 0.13208)
		(layer "B.Cu")
		(net "CLK_25M_CK440_CPU0_R_DP")
	)
	(segment
		(start 245.220236 -109.73054)
		(end 245.044214 -109.73054)
		(width 0.13208)
		(layer "B.Cu")
		(net "CLK_25M_CK440_CPU0_R_DP")
	)
	(segment
		(start 337.241642 -137.832338)
		(end 337.115404 -137.832338)
		(width 0.13208)
		(layer "B.Cu")
		(net "CLK_25M_CK440_CPU0_R_DP")
	)
	(segment
		(start 325.22033 -129.696972)
		(end 317.950596 -126.685802)
		(width 0.13208)
		(layer "B.Cu")
		(net "CLK_25M_CK440_CPU0_R_DP")
	)
	(segment
		(start 244.329204 -109.01553)
		(end 244.059456 -108.745782)
		(width 0.13208)
		(layer "B.Cu")
		(net "CLK_25M_CK440_CPU0_R_DP")
	)
	(segment
		(start 242.629436 -107.315762)
		(end 242.629436 -107.13974)
		(width 0.13208)
		(layer "B.Cu")
		(net "CLK_25M_CK440_CPU0_R_DP")
	)
	(segment
		(start 246.505476 -111.191802)
		(end 246.235728 -110.922054)
		(width 0.13208)
		(layer "B.Cu")
		(net "CLK_25M_CK440_CPU0_R_DP")
	)
	(segment
		(start 242.629436 -107.13974)
		(end 242.360196 -106.8705)
		(width 0.13208)
		(layer "B.Cu")
		(net "CLK_25M_CK440_CPU0_R_DP")
	)
	(segment
		(start 241.058446 -106.99496)
		(end 240.933986 -106.8705)
		(width 0.13208)
		(layer "B.Cu")
		(net "CLK_25M_CK440_CPU0_R_DP")
	)
	(segment
		(start 246.681498 -111.191802)
		(end 246.505476 -111.191802)
		(width 0.13208)
		(layer "B.Cu")
		(net "CLK_25M_CK440_CPU0_R_DP")
	)
	(segment
		(start 240.933986 -106.8705)
		(end 240.552986 -106.8705)
		(width 0.13208)
		(layer "B.Cu")
		(net "CLK_25M_CK440_CPU0_R_DP")
	)
	(segment
		(start 243.344446 -107.85475)
		(end 243.075206 -107.58551)
		(width 0.13208)
		(layer "B.Cu")
		(net "CLK_25M_CK440_CPU0_R_DP")
	)
	(segment
		(start 241.439446 -106.99496)
		(end 241.058446 -106.99496)
		(width 0.13208)
		(layer "B.Cu")
		(net "CLK_25M_CK440_CPU0_R_DP")
	)
	(segment
		(start 254.642366 -114.09299)
		(end 247.379744 -111.890048)
		(width 0.13208)
		(layer "B.Cu")
		(net "CLK_25M_CK440_CPU0_R_DP")
	)
	(segment
		(start 238.726726 -108.128054)
		(end 239.028986 -107.825794)
		(width 0.13208)
		(layer "B.Cu")
		(net "CLK_25M_CK440_CPU0_R_DP")
	)
	(segment
		(start 245.966488 -110.476792)
		(end 245.790466 -110.476792)
		(width 0.13208)
		(layer "B.Cu")
		(net "CLK_25M_CK440_CPU0_R_DP")
	)
	(segment
		(start 246.235728 -110.922054)
		(end 246.235728 -110.746032)
		(width 0.13208)
		(layer "B.Cu")
		(net "CLK_25M_CK440_CPU0_R_DP")
	)
	(segment
		(start 243.790216 -108.30052)
		(end 243.614194 -108.30052)
		(width 0.13208)
		(layer "B.Cu")
		(net "CLK_25M_CK440_CPU0_R_DP")
	)
	(segment
		(start 244.774466 -109.460792)
		(end 244.774466 -109.28477)
		(width 0.13208)
		(layer "B.Cu")
		(net "CLK_25M_CK440_CPU0_R_DP")
	)
	(segment
		(start 244.059456 -108.56976)
		(end 243.790216 -108.30052)
		(width 0.13208)
		(layer "B.Cu")
		(net "CLK_25M_CK440_CPU0_R_DP")
	)
	(segment
		(start 245.520718 -110.207044)
		(end 245.520718 -110.031022)
		(width 0.13208)
		(layer "B.Cu")
		(net "CLK_25M_CK440_CPU0_R_DP")
	)
	(segment
		(start 239.923066 -106.8705)
		(end 238.665512 -106.8705)
		(width 0.13208)
		(layer "B.Cu")
		(net "CLK_25M_CK440_CPU0_R_DP")
	)
	(segment
		(start 240.428526 -106.99496)
		(end 240.047526 -106.99496)
		(width 0.13208)
		(layer "B.Cu")
		(net "CLK_25M_CK440_CPU0_R_DP")
	)
	(segment
		(start 238.46282 -107.073192)
		(end 238.46282 -107.906058)
		(width 0.13208)
		(layer "B.Cu")
		(net "CLK_25M_CK440_CPU0_R_DP")
	)
	(segment
		(start 242.360196 -106.8705)
		(end 241.563906 -106.8705)
		(width 0.13208)
		(layer "B.Cu")
		(net "CLK_25M_CK440_CPU0_R_DP")
	)
	(segment
		(start 241.563906 -106.8705)
		(end 241.439446 -106.99496)
		(width 0.13208)
		(layer "B.Cu")
		(net "CLK_25M_CK440_CPU0_R_DP")
	)
	(segment
		(start 244.774466 -109.28477)
		(end 244.505226 -109.01553)
		(width 0.13208)
		(layer "B.Cu")
		(net "CLK_25M_CK440_CPU0_R_DP")
	)
	(segment
		(start 245.520718 -110.031022)
		(end 245.220236 -109.73054)
		(width 0.13208)
		(layer "B.Cu")
		(net "CLK_25M_CK440_CPU0_R_DP")
	)
	(segment
		(start 240.539016 -108.387134)
		(end 239.331246 -108.387134)
		(width 0.13208)
		(layer "F.Cu")
		(net "CLK_25M_CK440_CPU0_R_DN")
	)
	(segment
		(start 240.895378 -108.743496)
		(end 240.539016 -108.387134)
		(width 0.13208)
		(layer "F.Cu")
		(net "CLK_25M_CK440_CPU0_R_DN")
	)
	(segment
		(start 239.331246 -108.387134)
		(end 239.028986 -108.689394)
		(width 0.13208)
		(layer "F.Cu")
		(net "CLK_25M_CK440_CPU0_R_DN")
	)
	(via
		(at 239.028986 -108.689394)
		(size 0.508)
		(drill 0.254)
		(layers "F.Cu" "B.Cu")
		(net "CLK_25M_CK440_CPU0_R_DN")
	)
	(segment
		(start 337.222084 -136.479534)
		(end 337.033108 -136.479534)
		(width 0.13208)
		(layer "B.Cu")
		(net "CLK_25M_CK440_CPU0_R_DN")
	)
	(segment
		(start 238.726726 -108.387134)
		(end 239.028986 -108.689394)
		(width 0.13208)
		(layer "B.Cu")
		(net "CLK_25M_CK440_CPU0_R_DN")
	)
	(segment
		(start 238.55807 -106.61142)
		(end 238.20374 -106.96575)
		(width 0.13208)
		(layer "B.Cu")
		(net "CLK_25M_CK440_CPU0_R_DN")
	)
	(segment
		(start 238.515652 -108.387134)
		(end 238.726726 -108.387134)
		(width 0.13208)
		(layer "B.Cu")
		(net "CLK_25M_CK440_CPU0_R_DN")
	)
	(segment
		(start 238.20374 -106.96575)
		(end 238.20374 -107.95762)
		(width 0.13208)
		(layer "B.Cu")
		(net "CLK_25M_CK440_CPU0_R_DN")
	)
	(segment
		(start 318.026288 -126.436628)
		(end 254.705358 -113.841276)
		(width 0.13208)
		(layer "B.Cu")
		(net "CLK_25M_CK440_CPU0_R_DN")
	)
	(segment
		(start 337.033108 -136.479534)
		(end 336.55254 -136.960102)
		(width 0.13208)
		(layer "B.Cu")
		(net "CLK_25M_CK440_CPU0_R_DN")
	)
	(segment
		(start 238.286798 -108.15828)
		(end 238.515652 -108.387134)
		(width 0.13208)
		(layer "B.Cu")
		(net "CLK_25M_CK440_CPU0_R_DN")
	)
	(segment
		(start 242.467638 -106.61142)
		(end 238.55807 -106.61142)
		(width 0.13208)
		(layer "B.Cu")
		(net "CLK_25M_CK440_CPU0_R_DN")
	)
	(segment
		(start 336.55254 -136.960102)
		(end 335.473802 -136.960102)
		(width 0.13208)
		(layer "B.Cu")
		(net "CLK_25M_CK440_CPU0_R_DN")
	)
	(segment
		(start 254.705358 -113.841276)
		(end 247.517158 -111.66094)
		(width 0.13208)
		(layer "B.Cu")
		(net "CLK_25M_CK440_CPU0_R_DN")
	)
	(segment
		(start 238.20374 -107.95762)
		(end 238.286798 -108.15828)
		(width 0.13208)
		(layer "B.Cu")
		(net "CLK_25M_CK440_CPU0_R_DN")
	)
	(segment
		(start 335.473802 -136.960102)
		(end 330.994512 -135.104632)
		(width 0.13208)
		(layer "B.Cu")
		(net "CLK_25M_CK440_CPU0_R_DN")
	)
	(segment
		(start 247.517158 -111.66094)
		(end 242.467638 -106.61142)
		(width 0.13208)
		(layer "B.Cu")
		(net "CLK_25M_CK440_CPU0_R_DN")
	)
	(segment
		(start 330.994512 -135.104632)
		(end 325.367142 -129.477262)
		(width 0.13208)
		(layer "B.Cu")
		(net "CLK_25M_CK440_CPU0_R_DN")
	)
	(segment
		(start 325.367142 -129.477262)
		(end 318.026288 -126.436628)
		(width 0.13208)
		(layer "B.Cu")
		(net "CLK_25M_CK440_CPU0_R_DN")
	)
	(segment
		(start 251.615956 -100.813108)
		(end 251.495306 -100.933758)
		(width 0.13208)
		(layer "F.Cu")
		(net "CLK_25M_CK440_CPU0_DP")
	)
	(segment
		(start 242.071398 -108.128054)
		(end 241.715036 -107.771692)
		(width 0.13208)
		(layer "F.Cu")
		(net "CLK_25M_CK440_CPU0_DP")
	)
	(segment
		(start 251.495306 -100.933758)
		(end 251.24664 -100.933758)
		(width 0.13208)
		(layer "F.Cu")
		(net "CLK_25M_CK440_CPU0_DP")
	)
	(segment
		(start 251.24664 -100.933758)
		(end 248.203466 -102.658926)
		(width 0.13208)
		(layer "F.Cu")
		(net "CLK_25M_CK440_CPU0_DP")
	)
	(segment
		(start 242.734338 -108.128054)
		(end 242.071398 -108.128054)
		(width 0.13208)
		(layer "F.Cu")
		(net "CLK_25M_CK440_CPU0_DP")
	)
	(segment
		(start 248.203466 -102.658926)
		(end 242.734338 -108.128054)
		(width 0.13208)
		(layer "F.Cu")
		(net "CLK_25M_CK440_CPU0_DP")
	)
	(segment
		(start 251.807726 -100.813108)
		(end 251.615956 -100.813108)
		(width 0.13208)
		(layer "F.Cu")
		(net "CLK_25M_CK440_CPU0_DP")
	)
	(segment
		(start 251.807726 -101.313234)
		(end 251.610622 -101.313234)
		(width 0.13208)
		(layer "F.Cu")
		(net "CLK_25M_CK440_CPU0_DN")
	)
	(segment
		(start 242.05184 -108.387134)
		(end 241.695478 -108.743496)
		(width 0.13208)
		(layer "F.Cu")
		(net "CLK_25M_CK440_CPU0_DN")
	)
	(segment
		(start 242.84178 -108.387134)
		(end 242.05184 -108.387134)
		(width 0.13208)
		(layer "F.Cu")
		(net "CLK_25M_CK440_CPU0_DN")
	)
	(segment
		(start 248.361962 -102.867206)
		(end 242.84178 -108.387134)
		(width 0.13208)
		(layer "F.Cu")
		(net "CLK_25M_CK440_CPU0_DN")
	)
	(segment
		(start 251.490226 -101.192838)
		(end 251.31522 -101.192838)
		(width 0.13208)
		(layer "F.Cu")
		(net "CLK_25M_CK440_CPU0_DN")
	)
	(segment
		(start 251.610622 -101.313234)
		(end 251.490226 -101.192838)
		(width 0.13208)
		(layer "F.Cu")
		(net "CLK_25M_CK440_CPU0_DN")
	)
	(segment
		(start 251.31522 -101.192838)
		(end 248.361962 -102.867206)
		(width 0.13208)
		(layer "F.Cu")
		(net "CLK_25M_CK440_CPU0_DN")
	)
	(segment
		(start 329.419966 -29.708348)
		(end 329.419966 -29.164534)
		(width 0.12954)
		(layer "F.Cu")
		(net "CLK_24M_66M_LPC0_ESPI")
	)
	(segment
		(start 329.419966 -29.164534)
		(end 329.795378 -28.258008)
		(width 0.12954)
		(layer "F.Cu")
		(net "CLK_24M_66M_LPC0_ESPI")
	)
	(segment
		(start 332.143354 -37.399976)
		(end 332.153768 -37.452808)
		(width 0.0889)
		(layer "F.Cu")
		(net "CLK_24M_66M_LPC0_ESPI")
	)
	(segment
		(start 332.119478 -38.223444)
		(end 332.225142 -38.345618)
		(width 0.0889)
		(layer "F.Cu")
		(net "CLK_24M_66M_LPC0_ESPI")
	)
	(segment
		(start 332.101952 -37.869368)
		(end 332.057502 -37.935916)
		(width 0.0889)
		(layer "F.Cu")
		(net "CLK_24M_66M_LPC0_ESPI")
	)
	(segment
		(start 329.467972 -29.728414)
		(end 330.516484 -32.258762)
		(width 0.0889)
		(layer "F.Cu")
		(net "CLK_24M_66M_LPC0_ESPI")
	)
	(segment
		(start 332.143354 -35.14598)
		(end 332.143354 -37.399976)
		(width 0.0889)
		(layer "F.Cu")
		(net "CLK_24M_66M_LPC0_ESPI")
	)
	(segment
		(start 332.180692 -37.790628)
		(end 332.101952 -37.869368)
		(width 0.0889)
		(layer "F.Cu")
		(net "CLK_24M_66M_LPC0_ESPI")
	)
	(segment
		(start 331.129894 -33.364678)
		(end 331.129894 -34.13252)
		(width 0.0889)
		(layer "F.Cu")
		(net "CLK_24M_66M_LPC0_ESPI")
	)
	(segment
		(start 329.419966 -29.708348)
		(end 329.467972 -29.728414)
		(width 0.0889)
		(layer "F.Cu")
		(net "CLK_24M_66M_LPC0_ESPI")
	)
	(segment
		(start 332.397608 -38.518084)
		(end 332.397608 -38.880288)
		(width 0.0889)
		(layer "F.Cu")
		(net "CLK_24M_66M_LPC0_ESPI")
	)
	(segment
		(start 332.180692 -37.701474)
		(end 332.180692 -37.790628)
		(width 0.0889)
		(layer "F.Cu")
		(net "CLK_24M_66M_LPC0_ESPI")
	)
	(segment
		(start 332.057502 -37.935916)
		(end 332.057502 -38.05682)
		(width 0.0889)
		(layer "F.Cu")
		(net "CLK_24M_66M_LPC0_ESPI")
	)
	(segment
		(start 332.180692 -37.479732)
		(end 332.180692 -37.588698)
		(width 0.0889)
		(layer "F.Cu")
		(net "CLK_24M_66M_LPC0_ESPI")
	)
	(segment
		(start 332.153768 -37.452808)
		(end 332.180692 -37.479732)
		(width 0.0889)
		(layer "F.Cu")
		(net "CLK_24M_66M_LPC0_ESPI")
	)
	(segment
		(start 331.129894 -34.13252)
		(end 332.143354 -35.14598)
		(width 0.0889)
		(layer "F.Cu")
		(net "CLK_24M_66M_LPC0_ESPI")
	)
	(segment
		(start 332.180692 -37.588698)
		(end 332.19517 -37.66185)
		(width 0.0889)
		(layer "F.Cu")
		(net "CLK_24M_66M_LPC0_ESPI")
	)
	(segment
		(start 332.225142 -38.345618)
		(end 332.397608 -38.518084)
		(width 0.0889)
		(layer "F.Cu")
		(net "CLK_24M_66M_LPC0_ESPI")
	)
	(segment
		(start 332.057502 -38.05682)
		(end 332.119478 -38.223444)
		(width 0.0889)
		(layer "F.Cu")
		(net "CLK_24M_66M_LPC0_ESPI")
	)
	(segment
		(start 329.795378 -28.258008)
		(end 329.795378 -27.442668)
		(width 0.12954)
		(layer "F.Cu")
		(net "CLK_24M_66M_LPC0_ESPI")
	)
	(segment
		(start 330.516484 -32.751268)
		(end 331.129894 -33.364678)
		(width 0.0889)
		(layer "F.Cu")
		(net "CLK_24M_66M_LPC0_ESPI")
	)
	(segment
		(start 332.19517 -37.66185)
		(end 332.180692 -37.701474)
		(width 0.0889)
		(layer "F.Cu")
		(net "CLK_24M_66M_LPC0_ESPI")
	)
	(segment
		(start 330.516484 -32.258762)
		(end 330.516484 -32.751268)
		(width 0.0889)
		(layer "F.Cu")
		(net "CLK_24M_66M_LPC0_ESPI")
	)
	(via
		(at 329.419966 -29.708348)
		(size 0.762)
		(drill 0.381)
		(layers "F.Cu" "B.Cu")
		(net "CLK_24M_66M_LPC0_ESPI")
	)
	(segment
		(start 331.187044 -76.553568)
		(end 331.502258 -76.868782)
		(width 0.13208)
		(layer "F.Cu")
		(net "CLK_100M_PE_M2_0_DP")
	)
	(segment
		(start 331.099668 -76.553568)
		(end 331.187044 -76.553568)
		(width 0.13208)
		(layer "F.Cu")
		(net "CLK_100M_PE_M2_0_DP")
	)
	(segment
		(start 177.885344 -42.920412)
		(end 177.764948 -42.800016)
		(width 0.13208)
		(layer "F.Cu")
		(net "CLK_100M_PE_M2_0_DP")
	)
	(segment
		(start 331.502258 -76.868782)
		(end 331.502258 -77.701902)
		(width 0.13208)
		(layer "F.Cu")
		(net "CLK_100M_PE_M2_0_DP")
	)
	(segment
		(start 178.97094 -42.920412)
		(end 177.885344 -42.920412)
		(width 0.13208)
		(layer "F.Cu")
		(net "CLK_100M_PE_M2_0_DP")
	)
	(segment
		(start 179.2732 -42.618152)
		(end 178.97094 -42.920412)
		(width 0.13208)
		(layer "F.Cu")
		(net "CLK_100M_PE_M2_0_DP")
	)
	(segment
		(start 177.764948 -42.800016)
		(end 177.108104 -42.800016)
		(width 0.13208)
		(layer "F.Cu")
		(net "CLK_100M_PE_M2_0_DP")
	)
	(segment
		(start 331.502258 -77.701902)
		(end 331.226668 -77.977492)
		(width 0.13208)
		(layer "F.Cu")
		(net "CLK_100M_PE_M2_0_DP")
	)
	(via
		(at 179.2732 -42.618152)
		(size 0.508)
		(drill 0.254)
		(layers "F.Cu" "B.Cu")
		(net "CLK_100M_PE_M2_0_DP")
	)
	(via
		(at 331.226668 -77.977492)
		(size 0.508)
		(drill 0.254)
		(layers "F.Cu" "B.Cu")
		(net "CLK_100M_PE_M2_0_DP")
	)
	(segment
		(start 304.98542 -85.904578)
		(end 302.653954 -86.870286)
		(width 0.14732)
		(layer "In4.Cu")
		(net "CLK_100M_PE_M2_0_DP")
	)
	(segment
		(start 317.112904 -83.349846)
		(end 316.751208 -83.421728)
		(width 0.14732)
		(layer "In4.Cu")
		(net "CLK_100M_PE_M2_0_DP")
	)
	(segment
		(start 330.636118 -80.174846)
		(end 330.375514 -80.43545)
		(width 0.14732)
		(layer "In4.Cu")
		(net "CLK_100M_PE_M2_0_DP")
	)
	(segment
		(start 316.64148 -83.58632)
		(end 316.280292 -83.657948)
		(width 0.14732)
		(layer "In4.Cu")
		(net "CLK_100M_PE_M2_0_DP")
	)
	(segment
		(start 317.747904 -83.223354)
		(end 317.638176 -83.387946)
		(width 0.14732)
		(layer "In4.Cu")
		(net "CLK_100M_PE_M2_0_DP")
	)
	(segment
		(start 318.273684 -83.2612)
		(end 318.1096 -83.151472)
		(width 0.14732)
		(layer "In4.Cu")
		(net "CLK_100M_PE_M2_0_DP")
	)
	(segment
		(start 330.375514 -80.633062)
		(end 329.479656 -81.52892)
		(width 0.14732)
		(layer "In4.Cu")
		(net "CLK_100M_PE_M2_0_DP")
	)
	(segment
		(start 316.751208 -83.421728)
		(end 316.64148 -83.58632)
		(width 0.14732)
		(layer "In4.Cu")
		(net "CLK_100M_PE_M2_0_DP")
	)
	(segment
		(start 331.09408 -79.914496)
		(end 330.83373 -80.174846)
		(width 0.14732)
		(layer "In4.Cu")
		(net "CLK_100M_PE_M2_0_DP")
	)
	(segment
		(start 329.479656 -81.52892)
		(end 327.21804 -82.465672)
		(width 0.14732)
		(layer "In4.Cu")
		(net "CLK_100M_PE_M2_0_DP")
	)
	(segment
		(start 240.294414 -74.112882)
		(end 222.71609 -66.831718)
		(width 0.14732)
		(layer "In4.Cu")
		(net "CLK_100M_PE_M2_0_DP")
	)
	(segment
		(start 302.653954 -86.870286)
		(end 265.529568 -86.870286)
		(width 0.14732)
		(layer "In4.Cu")
		(net "CLK_100M_PE_M2_0_DP")
	)
	(segment
		(start 222.71609 -66.831718)
		(end 219.192602 -65.570862)
		(width 0.14732)
		(layer "In4.Cu")
		(net "CLK_100M_PE_M2_0_DP")
	)
	(segment
		(start 315.754512 -83.620102)
		(end 315.645038 -83.78444)
		(width 0.14732)
		(layer "In4.Cu")
		(net "CLK_100M_PE_M2_0_DP")
	)
	(segment
		(start 318.1096 -83.151472)
		(end 317.747904 -83.223354)
		(width 0.14732)
		(layer "In4.Cu")
		(net "CLK_100M_PE_M2_0_DP")
	)
	(segment
		(start 219.192602 -65.570862)
		(end 202.7428 -60.580778)
		(width 0.14732)
		(layer "In4.Cu")
		(net "CLK_100M_PE_M2_0_DP")
	)
	(segment
		(start 316.116208 -83.54822)
		(end 315.754512 -83.620102)
		(width 0.14732)
		(layer "In4.Cu")
		(net "CLK_100M_PE_M2_0_DP")
	)
	(segment
		(start 182.218076 -42.912792)
		(end 179.56784 -42.912792)
		(width 0.14732)
		(layer "In4.Cu")
		(net "CLK_100M_PE_M2_0_DP")
	)
	(segment
		(start 315.645038 -83.78444)
		(end 304.98542 -85.904578)
		(width 0.14732)
		(layer "In4.Cu")
		(net "CLK_100M_PE_M2_0_DP")
	)
	(segment
		(start 331.53096 -78.281784)
		(end 331.53096 -78.860142)
		(width 0.14732)
		(layer "In4.Cu")
		(net "CLK_100M_PE_M2_0_DP")
	)
	(segment
		(start 198.451978 -58.00852)
		(end 184.160668 -43.717464)
		(width 0.14732)
		(layer "In4.Cu")
		(net "CLK_100M_PE_M2_0_DP")
	)
	(segment
		(start 331.53096 -78.860142)
		(end 331.09408 -79.914496)
		(width 0.14732)
		(layer "In4.Cu")
		(net "CLK_100M_PE_M2_0_DP")
	)
	(segment
		(start 202.7428 -60.580778)
		(end 198.451978 -58.00852)
		(width 0.14732)
		(layer "In4.Cu")
		(net "CLK_100M_PE_M2_0_DP")
	)
	(segment
		(start 330.375514 -80.43545)
		(end 330.375514 -80.633062)
		(width 0.14732)
		(layer "In4.Cu")
		(net "CLK_100M_PE_M2_0_DP")
	)
	(segment
		(start 245.527068 -79.345536)
		(end 240.294414 -74.112882)
		(width 0.14732)
		(layer "In4.Cu")
		(net "CLK_100M_PE_M2_0_DP")
	)
	(segment
		(start 255.830324 -82.852768)
		(end 253.994158 -82.852768)
		(width 0.14732)
		(layer "In4.Cu")
		(net "CLK_100M_PE_M2_0_DP")
	)
	(segment
		(start 325.2724 -82.852768)
		(end 320.328036 -82.852768)
		(width 0.14732)
		(layer "In4.Cu")
		(net "CLK_100M_PE_M2_0_DP")
	)
	(segment
		(start 331.226668 -77.977492)
		(end 331.53096 -78.281784)
		(width 0.14732)
		(layer "In4.Cu")
		(net "CLK_100M_PE_M2_0_DP")
	)
	(segment
		(start 316.280292 -83.657948)
		(end 316.116208 -83.54822)
		(width 0.14732)
		(layer "In4.Cu")
		(net "CLK_100M_PE_M2_0_DP")
	)
	(segment
		(start 253.994158 -82.852768)
		(end 245.527068 -79.345536)
		(width 0.14732)
		(layer "In4.Cu")
		(net "CLK_100M_PE_M2_0_DP")
	)
	(segment
		(start 184.160668 -43.717464)
		(end 182.218076 -42.912792)
		(width 0.14732)
		(layer "In4.Cu")
		(net "CLK_100M_PE_M2_0_DP")
	)
	(segment
		(start 317.638176 -83.387946)
		(end 317.276988 -83.459574)
		(width 0.14732)
		(layer "In4.Cu")
		(net "CLK_100M_PE_M2_0_DP")
	)
	(segment
		(start 317.276988 -83.459574)
		(end 317.112904 -83.349846)
		(width 0.14732)
		(layer "In4.Cu")
		(net "CLK_100M_PE_M2_0_DP")
	)
	(segment
		(start 330.83373 -80.174846)
		(end 330.636118 -80.174846)
		(width 0.14732)
		(layer "In4.Cu")
		(net "CLK_100M_PE_M2_0_DP")
	)
	(segment
		(start 179.56784 -42.912792)
		(end 179.2732 -42.618152)
		(width 0.14732)
		(layer "In4.Cu")
		(net "CLK_100M_PE_M2_0_DP")
	)
	(segment
		(start 320.328036 -82.852768)
		(end 318.273684 -83.2612)
		(width 0.14732)
		(layer "In4.Cu")
		(net "CLK_100M_PE_M2_0_DP")
	)
	(segment
		(start 265.529568 -86.870286)
		(end 255.830324 -82.852768)
		(width 0.14732)
		(layer "In4.Cu")
		(net "CLK_100M_PE_M2_0_DP")
	)
	(segment
		(start 327.21804 -82.465672)
		(end 325.2724 -82.852768)
		(width 0.14732)
		(layer "In4.Cu")
		(net "CLK_100M_PE_M2_0_DP")
	)
	(segment
		(start 331.761338 -76.86929)
		(end 331.761338 -77.648562)
		(width 0.13208)
		(layer "F.Cu")
		(net "CLK_100M_PE_M2_0_DN")
	)
	(segment
		(start 179.2732 -43.481752)
		(end 178.97094 -43.179492)
		(width 0.13208)
		(layer "F.Cu")
		(net "CLK_100M_PE_M2_0_DN")
	)
	(segment
		(start 332.115668 -76.553568)
		(end 332.07706 -76.553568)
		(width 0.13208)
		(layer "F.Cu")
		(net "CLK_100M_PE_M2_0_DN")
	)
	(segment
		(start 177.869596 -43.179492)
		(end 177.7492 -43.299888)
		(width 0.13208)
		(layer "F.Cu")
		(net "CLK_100M_PE_M2_0_DN")
	)
	(segment
		(start 332.07706 -76.553568)
		(end 331.761338 -76.86929)
		(width 0.13208)
		(layer "F.Cu")
		(net "CLK_100M_PE_M2_0_DN")
	)
	(segment
		(start 177.7492 -43.299888)
		(end 177.108104 -43.299888)
		(width 0.13208)
		(layer "F.Cu")
		(net "CLK_100M_PE_M2_0_DN")
	)
	(segment
		(start 331.761338 -77.648562)
		(end 332.090268 -77.977492)
		(width 0.13208)
		(layer "F.Cu")
		(net "CLK_100M_PE_M2_0_DN")
	)
	(segment
		(start 178.97094 -43.179492)
		(end 177.869596 -43.179492)
		(width 0.13208)
		(layer "F.Cu")
		(net "CLK_100M_PE_M2_0_DN")
	)
	(via
		(at 179.2732 -43.481752)
		(size 0.508)
		(drill 0.254)
		(layers "F.Cu" "B.Cu")
		(net "CLK_100M_PE_M2_0_DN")
	)
	(via
		(at 332.090268 -77.977492)
		(size 0.508)
		(drill 0.254)
		(layers "F.Cu" "B.Cu")
		(net "CLK_100M_PE_M2_0_DN")
	)
	(segment
		(start 331.80528 -78.914752)
		(end 331.326744 -80.069944)
		(width 0.14732)
		(layer "In4.Cu")
		(net "CLK_100M_PE_M2_0_DN")
	)
	(segment
		(start 305.06543 -86.168738)
		(end 305.06543 -86.168484)
		(width 0.14732)
		(layer "In4.Cu")
		(net "CLK_100M_PE_M2_0_DN")
	)
	(segment
		(start 329.635104 -81.761584)
		(end 327.29805 -82.729578)
		(width 0.14732)
		(layer "In4.Cu")
		(net "CLK_100M_PE_M2_0_DN")
	)
	(segment
		(start 245.37162 -79.5782)
		(end 240.138966 -74.345546)
		(width 0.14732)
		(layer "In4.Cu")
		(net "CLK_100M_PE_M2_0_DN")
	)
	(segment
		(start 325.299578 -83.127088)
		(end 320.355214 -83.127088)
		(width 0.14732)
		(layer "In4.Cu")
		(net "CLK_100M_PE_M2_0_DN")
	)
	(segment
		(start 331.80528 -78.26248)
		(end 331.80528 -78.914752)
		(width 0.14732)
		(layer "In4.Cu")
		(net "CLK_100M_PE_M2_0_DN")
	)
	(segment
		(start 219.106496 -65.831466)
		(end 202.630786 -60.833508)
		(width 0.14732)
		(layer "In4.Cu")
		(net "CLK_100M_PE_M2_0_DN")
	)
	(segment
		(start 265.474958 -87.144606)
		(end 255.775714 -83.127088)
		(width 0.14732)
		(layer "In4.Cu")
		(net "CLK_100M_PE_M2_0_DN")
	)
	(segment
		(start 255.775714 -83.127088)
		(end 253.939548 -83.127088)
		(width 0.14732)
		(layer "In4.Cu")
		(net "CLK_100M_PE_M2_0_DN")
	)
	(segment
		(start 179.56784 -43.187112)
		(end 179.2732 -43.481752)
		(width 0.14732)
		(layer "In4.Cu")
		(net "CLK_100M_PE_M2_0_DN")
	)
	(segment
		(start 240.138966 -74.345546)
		(end 222.61703 -67.08775)
		(width 0.14732)
		(layer "In4.Cu")
		(net "CLK_100M_PE_M2_0_DN")
	)
	(segment
		(start 253.939548 -83.127088)
		(end 245.37162 -79.5782)
		(width 0.14732)
		(layer "In4.Cu")
		(net "CLK_100M_PE_M2_0_DN")
	)
	(segment
		(start 327.29805 -82.729578)
		(end 325.299578 -83.127088)
		(width 0.14732)
		(layer "In4.Cu")
		(net "CLK_100M_PE_M2_0_DN")
	)
	(segment
		(start 302.708564 -87.144606)
		(end 265.474958 -87.144606)
		(width 0.14732)
		(layer "In4.Cu")
		(net "CLK_100M_PE_M2_0_DN")
	)
	(segment
		(start 202.630786 -60.833508)
		(end 198.281798 -58.226452)
		(width 0.14732)
		(layer "In4.Cu")
		(net "CLK_100M_PE_M2_0_DN")
	)
	(segment
		(start 332.090268 -77.977492)
		(end 331.80528 -78.26248)
		(width 0.14732)
		(layer "In4.Cu")
		(net "CLK_100M_PE_M2_0_DN")
	)
	(segment
		(start 182.163466 -43.187112)
		(end 179.56784 -43.187112)
		(width 0.14732)
		(layer "In4.Cu")
		(net "CLK_100M_PE_M2_0_DN")
	)
	(segment
		(start 331.326744 -80.069944)
		(end 329.635104 -81.761584)
		(width 0.14732)
		(layer "In4.Cu")
		(net "CLK_100M_PE_M2_0_DN")
	)
	(segment
		(start 320.355214 -83.127088)
		(end 305.06543 -86.168738)
		(width 0.14732)
		(layer "In4.Cu")
		(net "CLK_100M_PE_M2_0_DN")
	)
	(segment
		(start 198.281798 -58.226452)
		(end 184.00522 -43.950128)
		(width 0.14732)
		(layer "In4.Cu")
		(net "CLK_100M_PE_M2_0_DN")
	)
	(segment
		(start 305.06543 -86.168484)
		(end 302.708564 -87.144606)
		(width 0.14732)
		(layer "In4.Cu")
		(net "CLK_100M_PE_M2_0_DN")
	)
	(segment
		(start 184.00522 -43.950128)
		(end 182.163466 -43.187112)
		(width 0.14732)
		(layer "In4.Cu")
		(net "CLK_100M_PE_M2_0_DN")
	)
	(segment
		(start 222.61703 -67.08775)
		(end 219.106496 -65.831466)
		(width 0.14732)
		(layer "In4.Cu")
		(net "CLK_100M_PE_M2_0_DN")
	)
	(segment
		(start 231.769666 -119.156226)
		(end 232.03535 -119.156226)
		(width 0.13208)
		(layer "F.Cu")
		(net "CLK_100M_OCP_SFF_3_R_DP")
	)
	(segment
		(start 232.03535 -119.156226)
		(end 232.8672 -119.988076)
		(width 0.13208)
		(layer "F.Cu")
		(net "CLK_100M_OCP_SFF_3_R_DP")
	)
	(segment
		(start 231.3432 -118.72976)
		(end 231.769666 -119.156226)
		(width 0.13208)
		(layer "F.Cu")
		(net "CLK_100M_OCP_SFF_3_R_DP")
	)
	(segment
		(start 232.8672 -123.89866)
		(end 232.748074 -124.017786)
		(width 0.13208)
		(layer "F.Cu")
		(net "CLK_100M_OCP_SFF_3_R_DP")
	)
	(segment
		(start 230.960422 -118.110762)
		(end 231.086914 -118.110762)
		(width 0.13208)
		(layer "F.Cu")
		(net "CLK_100M_OCP_SFF_3_R_DP")
	)
	(segment
		(start 231.3432 -118.367048)
		(end 231.3432 -118.72976)
		(width 0.13208)
		(layer "F.Cu")
		(net "CLK_100M_OCP_SFF_3_R_DP")
	)
	(segment
		(start 232.8672 -119.988076)
		(end 232.8672 -123.89866)
		(width 0.13208)
		(layer "F.Cu")
		(net "CLK_100M_OCP_SFF_3_R_DP")
	)
	(segment
		(start 231.086914 -118.110762)
		(end 231.3432 -118.367048)
		(width 0.13208)
		(layer "F.Cu")
		(net "CLK_100M_OCP_SFF_3_R_DP")
	)
	(segment
		(start 231.858566 -118.110762)
		(end 231.60228 -118.367048)
		(width 0.13208)
		(layer "F.Cu")
		(net "CLK_100M_OCP_SFF_3_R_DN")
	)
	(segment
		(start 231.60228 -118.367048)
		(end 231.60228 -118.622318)
		(width 0.13208)
		(layer "F.Cu")
		(net "CLK_100M_OCP_SFF_3_R_DN")
	)
	(segment
		(start 233.12628 -123.89612)
		(end 233.247946 -124.017786)
		(width 0.13208)
		(layer "F.Cu")
		(net "CLK_100M_OCP_SFF_3_R_DN")
	)
	(segment
		(start 231.877108 -118.897146)
		(end 232.142792 -118.897146)
		(width 0.13208)
		(layer "F.Cu")
		(net "CLK_100M_OCP_SFF_3_R_DN")
	)
	(segment
		(start 231.976422 -118.110762)
		(end 231.858566 -118.110762)
		(width 0.13208)
		(layer "F.Cu")
		(net "CLK_100M_OCP_SFF_3_R_DN")
	)
	(segment
		(start 233.12628 -119.880634)
		(end 233.12628 -123.89612)
		(width 0.13208)
		(layer "F.Cu")
		(net "CLK_100M_OCP_SFF_3_R_DN")
	)
	(segment
		(start 232.142792 -118.897146)
		(end 233.12628 -119.880634)
		(width 0.13208)
		(layer "F.Cu")
		(net "CLK_100M_OCP_SFF_3_R_DN")
	)
	(segment
		(start 231.60228 -118.622318)
		(end 231.877108 -118.897146)
		(width 0.13208)
		(layer "F.Cu")
		(net "CLK_100M_OCP_SFF_3_R_DN")
	)
	(segment
		(start 446.141348 -7.612634)
		(end 445.96177 -7.792212)
		(width 0.13208)
		(layer "F.Cu")
		(net "CLK_100M_OCP_SFF_3_DP")
	)
	(segment
		(start 231.34066 -116.930424)
		(end 230.960422 -117.310662)
		(width 0.13208)
		(layer "F.Cu")
		(net "CLK_100M_OCP_SFF_3_DP")
	)
	(segment
		(start 446.141348 -7.015734)
		(end 446.141348 -7.612634)
		(width 0.13208)
		(layer "F.Cu")
		(net "CLK_100M_OCP_SFF_3_DP")
	)
	(segment
		(start 231.034336 -116.36629)
		(end 231.34066 -116.672614)
		(width 0.13208)
		(layer "F.Cu")
		(net "CLK_100M_OCP_SFF_3_DP")
	)
	(segment
		(start 445.839088 -6.713474)
		(end 446.141348 -7.015734)
		(width 0.13208)
		(layer "F.Cu")
		(net "CLK_100M_OCP_SFF_3_DP")
	)
	(segment
		(start 231.34066 -116.672614)
		(end 231.34066 -116.930424)
		(width 0.13208)
		(layer "F.Cu")
		(net "CLK_100M_OCP_SFF_3_DP")
	)
	(segment
		(start 445.96177 -7.792212)
		(end 445.96177 -8.320024)
		(width 0.13208)
		(layer "F.Cu")
		(net "CLK_100M_OCP_SFF_3_DP")
	)
	(via
		(at 231.034336 -116.36629)
		(size 0.508)
		(drill 0.254)
		(layers "F.Cu" "B.Cu")
		(net "CLK_100M_OCP_SFF_3_DP")
	)
	(via
		(at 445.839088 -6.713474)
		(size 0.508)
		(drill 0.254)
		(layers "F.Cu" "B.Cu")
		(net "CLK_100M_OCP_SFF_3_DP")
	)
	(segment
		(start 238.686594 -114.727228)
		(end 235.215176 -114.727228)
		(width 0.14732)
		(layer "In4.Cu")
		(net "CLK_100M_OCP_SFF_3_DP")
	)
	(segment
		(start 435.124606 -24.435562)
		(end 433.2351 -28.997148)
		(width 0.14732)
		(layer "In4.Cu")
		(net "CLK_100M_OCP_SFF_3_DP")
	)
	(segment
		(start 433.2351 -28.997148)
		(end 433.2351 -46.944534)
		(width 0.14732)
		(layer "In4.Cu")
		(net "CLK_100M_OCP_SFF_3_DP")
	)
	(segment
		(start 241.066828 -115.713256)
		(end 238.686594 -114.727228)
		(width 0.14732)
		(layer "In4.Cu")
		(net "CLK_100M_OCP_SFF_3_DP")
	)
	(segment
		(start 444.314326 -6.781546)
		(end 444.116714 -6.781546)
		(width 0.14732)
		(layer "In4.Cu")
		(net "CLK_100M_OCP_SFF_3_DP")
	)
	(segment
		(start 391.928604 -91.570556)
		(end 383.397252 -100.101908)
		(width 0.14732)
		(layer "In4.Cu")
		(net "CLK_100M_OCP_SFF_3_DP")
	)
	(segment
		(start 435.597046 -23.294848)
		(end 435.596792 -23.295102)
		(width 0.14732)
		(layer "In4.Cu")
		(net "CLK_100M_OCP_SFF_3_DP")
	)
	(segment
		(start 445.986408 -6.06298)
		(end 444.83528 -6.06298)
		(width 0.14732)
		(layer "In4.Cu")
		(net "CLK_100M_OCP_SFF_3_DP")
	)
	(segment
		(start 442.713872 -10.77341)
		(end 442.810646 -10.915904)
		(width 0.14732)
		(layer "In4.Cu")
		(net "CLK_100M_OCP_SFF_3_DP")
	)
	(segment
		(start 444.83528 -6.06298)
		(end 444.57493 -6.32333)
		(width 0.14732)
		(layer "In4.Cu")
		(net "CLK_100M_OCP_SFF_3_DP")
	)
	(segment
		(start 426.540168 -53.639466)
		(end 419.83025 -53.639466)
		(width 0.14732)
		(layer "In4.Cu")
		(net "CLK_100M_OCP_SFF_3_DP")
	)
	(segment
		(start 444.116714 -6.781546)
		(end 443.492128 -7.406132)
		(width 0.14732)
		(layer "In4.Cu")
		(net "CLK_100M_OCP_SFF_3_DP")
	)
	(segment
		(start 445.839088 -6.713474)
		(end 446.133728 -6.418834)
		(width 0.14732)
		(layer "In4.Cu")
		(net "CLK_100M_OCP_SFF_3_DP")
	)
	(segment
		(start 265.018012 -111.255048)
		(end 263.726422 -111.255048)
		(width 0.14732)
		(layer "In4.Cu")
		(net "CLK_100M_OCP_SFF_3_DP")
	)
	(segment
		(start 317.24854 -100.101908)
		(end 316.24778 -101.102668)
		(width 0.14732)
		(layer "In4.Cu")
		(net "CLK_100M_OCP_SFF_3_DP")
	)
	(segment
		(start 419.83025 -53.639466)
		(end 399.020538 -74.449178)
		(width 0.14732)
		(layer "In4.Cu")
		(net "CLK_100M_OCP_SFF_3_DP")
	)
	(segment
		(start 443.492128 -7.406132)
		(end 443.232794 -8.059166)
		(width 0.14732)
		(layer "In4.Cu")
		(net "CLK_100M_OCP_SFF_3_DP")
	)
	(segment
		(start 444.57493 -6.520942)
		(end 444.314326 -6.781546)
		(width 0.14732)
		(layer "In4.Cu")
		(net "CLK_100M_OCP_SFF_3_DP")
	)
	(segment
		(start 263.726422 -111.255048)
		(end 252.963172 -115.713256)
		(width 0.14732)
		(layer "In4.Cu")
		(net "CLK_100M_OCP_SFF_3_DP")
	)
	(segment
		(start 442.585602 -11.442192)
		(end 442.462158 -12.088114)
		(width 0.14732)
		(layer "In4.Cu")
		(net "CLK_100M_OCP_SFF_3_DP")
	)
	(segment
		(start 444.57493 -6.32333)
		(end 444.57493 -6.520942)
		(width 0.14732)
		(layer "In4.Cu")
		(net "CLK_100M_OCP_SFF_3_DP")
	)
	(segment
		(start 278.152352 -101.102668)
		(end 273.061938 -103.211122)
		(width 0.14732)
		(layer "In4.Cu")
		(net "CLK_100M_OCP_SFF_3_DP")
	)
	(segment
		(start 252.963172 -115.713256)
		(end 241.066828 -115.713256)
		(width 0.14732)
		(layer "In4.Cu")
		(net "CLK_100M_OCP_SFF_3_DP")
	)
	(segment
		(start 399.020538 -74.449178)
		(end 391.928604 -91.570556)
		(width 0.14732)
		(layer "In4.Cu")
		(net "CLK_100M_OCP_SFF_3_DP")
	)
	(segment
		(start 442.728604 -11.345418)
		(end 442.585602 -11.442192)
		(width 0.14732)
		(layer "In4.Cu")
		(net "CLK_100M_OCP_SFF_3_DP")
	)
	(segment
		(start 442.92393 -9.675622)
		(end 443.020704 -9.818116)
		(width 0.14732)
		(layer "In4.Cu")
		(net "CLK_100M_OCP_SFF_3_DP")
	)
	(segment
		(start 443.020704 -9.818116)
		(end 442.938662 -10.24763)
		(width 0.14732)
		(layer "In4.Cu")
		(net "CLK_100M_OCP_SFF_3_DP")
	)
	(segment
		(start 442.938662 -10.24763)
		(end 442.79566 -10.344404)
		(width 0.14732)
		(layer "In4.Cu")
		(net "CLK_100M_OCP_SFF_3_DP")
	)
	(segment
		(start 316.24778 -101.102668)
		(end 278.152352 -101.102668)
		(width 0.14732)
		(layer "In4.Cu")
		(net "CLK_100M_OCP_SFF_3_DP")
	)
	(segment
		(start 435.596792 -23.295102)
		(end 435.124352 -24.435562)
		(width 0.14732)
		(layer "In4.Cu")
		(net "CLK_100M_OCP_SFF_3_DP")
	)
	(segment
		(start 442.810646 -10.915904)
		(end 442.728604 -11.345418)
		(width 0.14732)
		(layer "In4.Cu")
		(net "CLK_100M_OCP_SFF_3_DP")
	)
	(segment
		(start 231.328976 -116.66093)
		(end 231.034336 -116.36629)
		(width 0.14732)
		(layer "In4.Cu")
		(net "CLK_100M_OCP_SFF_3_DP")
	)
	(segment
		(start 231.636824 -117.291104)
		(end 231.328976 -116.983256)
		(width 0.14732)
		(layer "In4.Cu")
		(net "CLK_100M_OCP_SFF_3_DP")
	)
	(segment
		(start 442.79566 -10.344404)
		(end 442.713872 -10.77341)
		(width 0.14732)
		(layer "In4.Cu")
		(net "CLK_100M_OCP_SFF_3_DP")
	)
	(segment
		(start 440.922664 -15.965424)
		(end 437.014112 -19.873976)
		(width 0.14732)
		(layer "In4.Cu")
		(net "CLK_100M_OCP_SFF_3_DP")
	)
	(segment
		(start 437.014112 -19.873976)
		(end 435.597046 -23.294848)
		(width 0.14732)
		(layer "In4.Cu")
		(net "CLK_100M_OCP_SFF_3_DP")
	)
	(segment
		(start 235.215176 -114.727228)
		(end 232.6513 -117.291104)
		(width 0.14732)
		(layer "In4.Cu")
		(net "CLK_100M_OCP_SFF_3_DP")
	)
	(segment
		(start 446.133728 -6.2103)
		(end 445.986408 -6.06298)
		(width 0.14732)
		(layer "In4.Cu")
		(net "CLK_100M_OCP_SFF_3_DP")
	)
	(segment
		(start 443.232794 -8.059166)
		(end 442.92393 -9.675622)
		(width 0.14732)
		(layer "In4.Cu")
		(net "CLK_100M_OCP_SFF_3_DP")
	)
	(segment
		(start 446.133728 -6.418834)
		(end 446.133728 -6.2103)
		(width 0.14732)
		(layer "In4.Cu")
		(net "CLK_100M_OCP_SFF_3_DP")
	)
	(segment
		(start 231.328976 -116.983256)
		(end 231.328976 -116.66093)
		(width 0.14732)
		(layer "In4.Cu")
		(net "CLK_100M_OCP_SFF_3_DP")
	)
	(segment
		(start 273.061938 -103.211122)
		(end 265.018012 -111.255048)
		(width 0.14732)
		(layer "In4.Cu")
		(net "CLK_100M_OCP_SFF_3_DP")
	)
	(segment
		(start 232.6513 -117.291104)
		(end 231.636824 -117.291104)
		(width 0.14732)
		(layer "In4.Cu")
		(net "CLK_100M_OCP_SFF_3_DP")
	)
	(segment
		(start 383.397252 -100.101908)
		(end 317.24854 -100.101908)
		(width 0.14732)
		(layer "In4.Cu")
		(net "CLK_100M_OCP_SFF_3_DP")
	)
	(segment
		(start 433.2351 -46.944534)
		(end 426.540168 -53.639466)
		(width 0.14732)
		(layer "In4.Cu")
		(net "CLK_100M_OCP_SFF_3_DP")
	)
	(segment
		(start 435.124352 -24.435562)
		(end 435.124606 -24.435562)
		(width 0.14732)
		(layer "In4.Cu")
		(net "CLK_100M_OCP_SFF_3_DP")
	)
	(segment
		(start 442.462158 -12.088114)
		(end 440.922664 -15.965424)
		(width 0.14732)
		(layer "In4.Cu")
		(net "CLK_100M_OCP_SFF_3_DP")
	)
	(segment
		(start 231.59974 -116.93398)
		(end 231.976422 -117.310662)
		(width 0.13208)
		(layer "F.Cu")
		(net "CLK_100M_OCP_SFF_3_DN")
	)
	(segment
		(start 231.59974 -116.664486)
		(end 231.59974 -116.93398)
		(width 0.13208)
		(layer "F.Cu")
		(net "CLK_100M_OCP_SFF_3_DN")
	)
	(segment
		(start 446.400428 -7.599934)
		(end 446.400428 -7.015734)
		(width 0.13208)
		(layer "F.Cu")
		(net "CLK_100M_OCP_SFF_3_DN")
	)
	(segment
		(start 446.561972 -7.761478)
		(end 446.400428 -7.599934)
		(width 0.13208)
		(layer "F.Cu")
		(net "CLK_100M_OCP_SFF_3_DN")
	)
	(segment
		(start 231.897936 -116.36629)
		(end 231.59974 -116.664486)
		(width 0.13208)
		(layer "F.Cu")
		(net "CLK_100M_OCP_SFF_3_DN")
	)
	(segment
		(start 446.561972 -8.320024)
		(end 446.561972 -7.761478)
		(width 0.13208)
		(layer "F.Cu")
		(net "CLK_100M_OCP_SFF_3_DN")
	)
	(segment
		(start 446.400428 -7.015734)
		(end 446.702688 -6.713474)
		(width 0.13208)
		(layer "F.Cu")
		(net "CLK_100M_OCP_SFF_3_DN")
	)
	(via
		(at 446.702688 -6.713474)
		(size 0.508)
		(drill 0.254)
		(layers "F.Cu" "B.Cu")
		(net "CLK_100M_OCP_SFF_3_DN")
	)
	(via
		(at 231.897936 -116.36629)
		(size 0.508)
		(drill 0.254)
		(layers "F.Cu" "B.Cu")
		(net "CLK_100M_OCP_SFF_3_DN")
	)
	(segment
		(start 317.134748 -99.827588)
		(end 316.133988 -100.828348)
		(width 0.14732)
		(layer "In4.Cu")
		(net "CLK_100M_OCP_SFF_3_DN")
	)
	(segment
		(start 235.101384 -114.452908)
		(end 234.275376 -115.278916)
		(width 0.14732)
		(layer "In4.Cu")
		(net "CLK_100M_OCP_SFF_3_DN")
	)
	(segment
		(start 231.750616 -117.016784)
		(end 231.603296 -116.869464)
		(width 0.14732)
		(layer "In4.Cu")
		(net "CLK_100M_OCP_SFF_3_DN")
	)
	(segment
		(start 232.537508 -117.016784)
		(end 231.750616 -117.016784)
		(width 0.14732)
		(layer "In4.Cu")
		(net "CLK_100M_OCP_SFF_3_DN")
	)
	(segment
		(start 442.19749 -12.011152)
		(end 440.688476 -15.8115)
		(width 0.14732)
		(layer "In4.Cu")
		(net "CLK_100M_OCP_SFF_3_DN")
	)
	(segment
		(start 432.96078 -28.942538)
		(end 432.96078 -46.830742)
		(width 0.14732)
		(layer "In4.Cu")
		(net "CLK_100M_OCP_SFF_3_DN")
	)
	(segment
		(start 236.04093 -114.313208)
		(end 235.90123 -114.452908)
		(width 0.14732)
		(layer "In4.Cu")
		(net "CLK_100M_OCP_SFF_3_DN")
	)
	(segment
		(start 263.671812 -110.980728)
		(end 252.908562 -115.438936)
		(width 0.14732)
		(layer "In4.Cu")
		(net "CLK_100M_OCP_SFF_3_DN")
	)
	(segment
		(start 278.097742 -100.828348)
		(end 272.90649 -102.978458)
		(width 0.14732)
		(layer "In4.Cu")
		(net "CLK_100M_OCP_SFF_3_DN")
	)
	(segment
		(start 241.121438 -115.438936)
		(end 238.741204 -114.452908)
		(width 0.14732)
		(layer "In4.Cu")
		(net "CLK_100M_OCP_SFF_3_DN")
	)
	(segment
		(start 391.69594 -91.415108)
		(end 383.28346 -99.827588)
		(width 0.14732)
		(layer "In4.Cu")
		(net "CLK_100M_OCP_SFF_3_DN")
	)
	(segment
		(start 233.81716 -115.53952)
		(end 233.81716 -115.737132)
		(width 0.14732)
		(layer "In4.Cu")
		(net "CLK_100M_OCP_SFF_3_DN")
	)
	(segment
		(start 442.654182 -9.623806)
		(end 442.19749 -12.011152)
		(width 0.14732)
		(layer "In4.Cu")
		(net "CLK_100M_OCP_SFF_3_DN")
	)
	(segment
		(start 233.098594 -116.455698)
		(end 232.537508 -117.016784)
		(width 0.14732)
		(layer "In4.Cu")
		(net "CLK_100M_OCP_SFF_3_DN")
	)
	(segment
		(start 446.408048 -6.418834)
		(end 446.408048 -6.096508)
		(width 0.14732)
		(layer "In4.Cu")
		(net "CLK_100M_OCP_SFF_3_DN")
	)
	(segment
		(start 443.25794 -7.252208)
		(end 442.968126 -7.982204)
		(width 0.14732)
		(layer "In4.Cu")
		(net "CLK_100M_OCP_SFF_3_DN")
	)
	(segment
		(start 235.90123 -114.452908)
		(end 235.101384 -114.452908)
		(width 0.14732)
		(layer "In4.Cu")
		(net "CLK_100M_OCP_SFF_3_DN")
	)
	(segment
		(start 234.275376 -115.278916)
		(end 234.077764 -115.278916)
		(width 0.14732)
		(layer "In4.Cu")
		(net "CLK_100M_OCP_SFF_3_DN")
	)
	(segment
		(start 398.787874 -74.29373)
		(end 391.69594 -91.415108)
		(width 0.14732)
		(layer "In4.Cu")
		(net "CLK_100M_OCP_SFF_3_DN")
	)
	(segment
		(start 264.90422 -110.980728)
		(end 263.671812 -110.980728)
		(width 0.14732)
		(layer "In4.Cu")
		(net "CLK_100M_OCP_SFF_3_DN")
	)
	(segment
		(start 272.90649 -102.978458)
		(end 264.90422 -110.980728)
		(width 0.14732)
		(layer "In4.Cu")
		(net "CLK_100M_OCP_SFF_3_DN")
	)
	(segment
		(start 231.603296 -116.869464)
		(end 231.603296 -116.66093)
		(width 0.14732)
		(layer "In4.Cu")
		(net "CLK_100M_OCP_SFF_3_DN")
	)
	(segment
		(start 383.28346 -99.827588)
		(end 317.134748 -99.827588)
		(width 0.14732)
		(layer "In4.Cu")
		(net "CLK_100M_OCP_SFF_3_DN")
	)
	(segment
		(start 444.721488 -5.78866)
		(end 444.002668 -6.507226)
		(width 0.14732)
		(layer "In4.Cu")
		(net "CLK_100M_OCP_SFF_3_DN")
	)
	(segment
		(start 236.54893 -114.452908)
		(end 236.40923 -114.313208)
		(width 0.14732)
		(layer "In4.Cu")
		(net "CLK_100M_OCP_SFF_3_DN")
	)
	(segment
		(start 426.426376 -53.365146)
		(end 419.716458 -53.365146)
		(width 0.14732)
		(layer "In4.Cu")
		(net "CLK_100M_OCP_SFF_3_DN")
	)
	(segment
		(start 440.688476 -15.8115)
		(end 436.781448 -19.718528)
		(width 0.14732)
		(layer "In4.Cu")
		(net "CLK_100M_OCP_SFF_3_DN")
	)
	(segment
		(start 442.968126 -7.982204)
		(end 442.654436 -9.623806)
		(width 0.14732)
		(layer "In4.Cu")
		(net "CLK_100M_OCP_SFF_3_DN")
	)
	(segment
		(start 233.55681 -115.997482)
		(end 233.359198 -115.997482)
		(width 0.14732)
		(layer "In4.Cu")
		(net "CLK_100M_OCP_SFF_3_DN")
	)
	(segment
		(start 446.702688 -6.713474)
		(end 446.408048 -6.418834)
		(width 0.14732)
		(layer "In4.Cu")
		(net "CLK_100M_OCP_SFF_3_DN")
	)
	(segment
		(start 419.716458 -53.365146)
		(end 398.787874 -74.29373)
		(width 0.14732)
		(layer "In4.Cu")
		(net "CLK_100M_OCP_SFF_3_DN")
	)
	(segment
		(start 444.002922 -6.507226)
		(end 443.25794 -7.252208)
		(width 0.14732)
		(layer "In4.Cu")
		(net "CLK_100M_OCP_SFF_3_DN")
	)
	(segment
		(start 442.654436 -9.623806)
		(end 442.654182 -9.623806)
		(width 0.14732)
		(layer "In4.Cu")
		(net "CLK_100M_OCP_SFF_3_DN")
	)
	(segment
		(start 231.603296 -116.66093)
		(end 231.897936 -116.36629)
		(width 0.14732)
		(layer "In4.Cu")
		(net "CLK_100M_OCP_SFF_3_DN")
	)
	(segment
		(start 252.908562 -115.438936)
		(end 241.121438 -115.438936)
		(width 0.14732)
		(layer "In4.Cu")
		(net "CLK_100M_OCP_SFF_3_DN")
	)
	(segment
		(start 436.781448 -19.718528)
		(end 432.96078 -28.942538)
		(width 0.14732)
		(layer "In4.Cu")
		(net "CLK_100M_OCP_SFF_3_DN")
	)
	(segment
		(start 236.40923 -114.313208)
		(end 236.04093 -114.313208)
		(width 0.14732)
		(layer "In4.Cu")
		(net "CLK_100M_OCP_SFF_3_DN")
	)
	(segment
		(start 446.408048 -6.096508)
		(end 446.1002 -5.78866)
		(width 0.14732)
		(layer "In4.Cu")
		(net "CLK_100M_OCP_SFF_3_DN")
	)
	(segment
		(start 238.741204 -114.452908)
		(end 236.54893 -114.452908)
		(width 0.14732)
		(layer "In4.Cu")
		(net "CLK_100M_OCP_SFF_3_DN")
	)
	(segment
		(start 446.1002 -5.78866)
		(end 444.721488 -5.78866)
		(width 0.14732)
		(layer "In4.Cu")
		(net "CLK_100M_OCP_SFF_3_DN")
	)
	(segment
		(start 234.077764 -115.278916)
		(end 233.81716 -115.53952)
		(width 0.14732)
		(layer "In4.Cu")
		(net "CLK_100M_OCP_SFF_3_DN")
	)
	(segment
		(start 432.96078 -46.830742)
		(end 426.426376 -53.365146)
		(width 0.14732)
		(layer "In4.Cu")
		(net "CLK_100M_OCP_SFF_3_DN")
	)
	(segment
		(start 233.098594 -116.258086)
		(end 233.098594 -116.455698)
		(width 0.14732)
		(layer "In4.Cu")
		(net "CLK_100M_OCP_SFF_3_DN")
	)
	(segment
		(start 444.002668 -6.507226)
		(end 444.002922 -6.507226)
		(width 0.14732)
		(layer "In4.Cu")
		(net "CLK_100M_OCP_SFF_3_DN")
	)
	(segment
		(start 233.359198 -115.997482)
		(end 233.098594 -116.258086)
		(width 0.14732)
		(layer "In4.Cu")
		(net "CLK_100M_OCP_SFF_3_DN")
	)
	(segment
		(start 233.81716 -115.737132)
		(end 233.55681 -115.997482)
		(width 0.14732)
		(layer "In4.Cu")
		(net "CLK_100M_OCP_SFF_3_DN")
	)
	(segment
		(start 316.133988 -100.828348)
		(end 278.097742 -100.828348)
		(width 0.14732)
		(layer "In4.Cu")
		(net "CLK_100M_OCP_SFF_3_DN")
	)
	(segment
		(start 229.580186 -122.804428)
		(end 230.460296 -122.804428)
		(width 0.13208)
		(layer "F.Cu")
		(net "CLK_100M_OCP_SFF_2_R_DP")
	)
	(segment
		(start 231.17556 -124.027184)
		(end 231.545638 -124.397262)
		(width 0.13208)
		(layer "F.Cu")
		(net "CLK_100M_OCP_SFF_2_R_DP")
	)
	(segment
		(start 229.216712 -123.167902)
		(end 229.580186 -122.804428)
		(width 0.13208)
		(layer "F.Cu")
		(net "CLK_100M_OCP_SFF_2_R_DP")
	)
	(segment
		(start 232.127298 -124.397262)
		(end 232.247948 -124.517912)
		(width 0.13208)
		(layer "F.Cu")
		(net "CLK_100M_OCP_SFF_2_R_DP")
	)
	(segment
		(start 230.460296 -122.804428)
		(end 231.17556 -123.519692)
		(width 0.13208)
		(layer "F.Cu")
		(net "CLK_100M_OCP_SFF_2_R_DP")
	)
	(segment
		(start 231.545638 -124.397262)
		(end 232.127298 -124.397262)
		(width 0.13208)
		(layer "F.Cu")
		(net "CLK_100M_OCP_SFF_2_R_DP")
	)
	(segment
		(start 231.17556 -123.519692)
		(end 231.17556 -124.027184)
		(width 0.13208)
		(layer "F.Cu")
		(net "CLK_100M_OCP_SFF_2_R_DP")
	)
	(segment
		(start 231.65308 -124.138182)
		(end 232.127552 -124.138182)
		(width 0.13208)
		(layer "F.Cu")
		(net "CLK_100M_OCP_SFF_2_R_DN")
	)
	(segment
		(start 230.567738 -122.545348)
		(end 231.43464 -123.41225)
		(width 0.13208)
		(layer "F.Cu")
		(net "CLK_100M_OCP_SFF_2_R_DN")
	)
	(segment
		(start 231.43464 -123.41225)
		(end 231.43464 -123.919742)
		(width 0.13208)
		(layer "F.Cu")
		(net "CLK_100M_OCP_SFF_2_R_DN")
	)
	(segment
		(start 229.216712 -122.151902)
		(end 229.610158 -122.545348)
		(width 0.13208)
		(layer "F.Cu")
		(net "CLK_100M_OCP_SFF_2_R_DN")
	)
	(segment
		(start 232.127552 -124.138182)
		(end 232.247948 -124.017786)
		(width 0.13208)
		(layer "F.Cu")
		(net "CLK_100M_OCP_SFF_2_R_DN")
	)
	(segment
		(start 231.43464 -123.919742)
		(end 231.65308 -124.138182)
		(width 0.13208)
		(layer "F.Cu")
		(net "CLK_100M_OCP_SFF_2_R_DN")
	)
	(segment
		(start 229.610158 -122.545348)
		(end 230.567738 -122.545348)
		(width 0.13208)
		(layer "F.Cu")
		(net "CLK_100M_OCP_SFF_2_R_DN")
	)
	(segment
		(start 446.140586 -11.966702)
		(end 446.140586 -12.562586)
		(width 0.13208)
		(layer "F.Cu")
		(net "CLK_100M_OCP_SFF_2_DP")
	)
	(segment
		(start 227.91166 -122.781568)
		(end 227.59924 -123.093988)
		(width 0.13208)
		(layer "F.Cu")
		(net "CLK_100M_OCP_SFF_2_DP")
	)
	(segment
		(start 228.030278 -122.781568)
		(end 227.91166 -122.781568)
		(width 0.13208)
		(layer "F.Cu")
		(net "CLK_100M_OCP_SFF_2_DP")
	)
	(segment
		(start 446.140586 -12.562586)
		(end 445.838326 -12.864846)
		(width 0.13208)
		(layer "F.Cu")
		(net "CLK_100M_OCP_SFF_2_DP")
	)
	(segment
		(start 445.96177 -11.26998)
		(end 445.96177 -11.787886)
		(width 0.13208)
		(layer "F.Cu")
		(net "CLK_100M_OCP_SFF_2_DP")
	)
	(segment
		(start 228.416612 -123.167902)
		(end 228.030278 -122.781568)
		(width 0.13208)
		(layer "F.Cu")
		(net "CLK_100M_OCP_SFF_2_DP")
	)
	(segment
		(start 445.96177 -11.787886)
		(end 446.140586 -11.966702)
		(width 0.13208)
		(layer "F.Cu")
		(net "CLK_100M_OCP_SFF_2_DP")
	)
	(via
		(at 445.838326 -12.864846)
		(size 0.508)
		(drill 0.254)
		(layers "F.Cu" "B.Cu")
		(net "CLK_100M_OCP_SFF_2_DP")
	)
	(via
		(at 227.59924 -123.093988)
		(size 0.508)
		(drill 0.254)
		(layers "F.Cu" "B.Cu")
		(net "CLK_100M_OCP_SFF_2_DP")
	)
	(segment
		(start 393.202414 -91.482418)
		(end 383.617724 -101.067108)
		(width 0.14732)
		(layer "In4.Cu")
		(net "CLK_100M_OCP_SFF_2_DP")
	)
	(segment
		(start 233.312462 -122.799348)
		(end 227.89388 -122.799348)
		(width 0.14732)
		(layer "In4.Cu")
		(net "CLK_100M_OCP_SFF_2_DP")
	)
	(segment
		(start 443.21984 -14.705584)
		(end 437.623204 -20.30222)
		(width 0.14732)
		(layer "In4.Cu")
		(net "CLK_100M_OCP_SFF_2_DP")
	)
	(segment
		(start 317.969646 -101.067108)
		(end 317.095886 -101.940868)
		(width 0.14732)
		(layer "In4.Cu")
		(net "CLK_100M_OCP_SFF_2_DP")
	)
	(segment
		(start 445.19088 -11.864848)
		(end 444.970408 -12.085574)
		(width 0.14732)
		(layer "In4.Cu")
		(net "CLK_100M_OCP_SFF_2_DP")
	)
	(segment
		(start 400.294348 -74.36104)
		(end 393.202414 -91.482418)
		(width 0.14732)
		(layer "In4.Cu")
		(net "CLK_100M_OCP_SFF_2_DP")
	)
	(segment
		(start 434.0733 -47.292006)
		(end 426.88764 -54.477666)
		(width 0.14732)
		(layer "In4.Cu")
		(net "CLK_100M_OCP_SFF_2_DP")
	)
	(segment
		(start 444.316612 -13.064236)
		(end 444.018416 -13.510514)
		(width 0.14732)
		(layer "In4.Cu")
		(net "CLK_100M_OCP_SFF_2_DP")
	)
	(segment
		(start 426.88764 -54.477666)
		(end 420.177722 -54.477666)
		(width 0.14732)
		(layer "In4.Cu")
		(net "CLK_100M_OCP_SFF_2_DP")
	)
	(segment
		(start 273.473418 -103.827326)
		(end 265.207496 -112.093248)
		(width 0.14732)
		(layer "In4.Cu")
		(net "CLK_100M_OCP_SFF_2_DP")
	)
	(segment
		(start 437.45404 -20.710652)
		(end 437.529732 -20.893024)
		(width 0.14732)
		(layer "In4.Cu")
		(net "CLK_100M_OCP_SFF_2_DP")
	)
	(segment
		(start 437.388762 -21.233638)
		(end 437.206136 -21.309076)
		(width 0.14732)
		(layer "In4.Cu")
		(net "CLK_100M_OCP_SFF_2_DP")
	)
	(segment
		(start 436.993538 -21.82241)
		(end 437.06923 -22.005036)
		(width 0.14732)
		(layer "In4.Cu")
		(net "CLK_100M_OCP_SFF_2_DP")
	)
	(segment
		(start 264.073894 -112.093248)
		(end 251.190252 -117.429788)
		(width 0.14732)
		(layer "In4.Cu")
		(net "CLK_100M_OCP_SFF_2_DP")
	)
	(segment
		(start 251.190252 -117.429788)
		(end 246.27586 -117.429788)
		(width 0.14732)
		(layer "In4.Cu")
		(net "CLK_100M_OCP_SFF_2_DP")
	)
	(segment
		(start 227.89388 -122.799348)
		(end 227.59924 -123.093988)
		(width 0.14732)
		(layer "In4.Cu")
		(net "CLK_100M_OCP_SFF_2_DP")
	)
	(segment
		(start 246.27586 -117.429788)
		(end 233.312462 -122.799348)
		(width 0.14732)
		(layer "In4.Cu")
		(net "CLK_100M_OCP_SFF_2_DP")
	)
	(segment
		(start 383.617724 -101.067108)
		(end 317.969646 -101.067108)
		(width 0.14732)
		(layer "In4.Cu")
		(net "CLK_100M_OCP_SFF_2_DP")
	)
	(segment
		(start 420.177722 -54.477666)
		(end 400.294348 -74.36104)
		(width 0.14732)
		(layer "In4.Cu")
		(net "CLK_100M_OCP_SFF_2_DP")
	)
	(segment
		(start 437.45404 -20.710398)
		(end 437.45404 -20.710652)
		(width 0.14732)
		(layer "In4.Cu")
		(net "CLK_100M_OCP_SFF_2_DP")
	)
	(segment
		(start 437.623204 -20.30222)
		(end 437.45404 -20.710398)
		(width 0.14732)
		(layer "In4.Cu")
		(net "CLK_100M_OCP_SFF_2_DP")
	)
	(segment
		(start 443.639956 -14.076934)
		(end 443.21984 -14.705584)
		(width 0.14732)
		(layer "In4.Cu")
		(net "CLK_100M_OCP_SFF_2_DP")
	)
	(segment
		(start 434.0733 -28.871926)
		(end 434.0733 -47.292006)
		(width 0.14732)
		(layer "In4.Cu")
		(net "CLK_100M_OCP_SFF_2_DP")
	)
	(segment
		(start 437.529732 -20.893024)
		(end 437.388762 -21.233638)
		(width 0.14732)
		(layer "In4.Cu")
		(net "CLK_100M_OCP_SFF_2_DP")
	)
	(segment
		(start 444.510668 -13.025374)
		(end 444.316612 -13.063982)
		(width 0.14732)
		(layer "In4.Cu")
		(net "CLK_100M_OCP_SFF_2_DP")
	)
	(segment
		(start 278.027384 -101.940868)
		(end 273.473418 -103.827326)
		(width 0.14732)
		(layer "In4.Cu")
		(net "CLK_100M_OCP_SFF_2_DP")
	)
	(segment
		(start 437.06923 -22.005036)
		(end 436.92826 -22.34565)
		(width 0.14732)
		(layer "In4.Cu")
		(net "CLK_100M_OCP_SFF_2_DP")
	)
	(segment
		(start 444.316612 -13.063982)
		(end 444.316612 -13.064236)
		(width 0.14732)
		(layer "In4.Cu")
		(net "CLK_100M_OCP_SFF_2_DP")
	)
	(segment
		(start 444.051944 -13.679678)
		(end 443.80912 -14.043152)
		(width 0.14732)
		(layer "In4.Cu")
		(net "CLK_100M_OCP_SFF_2_DP")
	)
	(segment
		(start 446.132966 -12.227814)
		(end 445.77 -11.864848)
		(width 0.14732)
		(layer "In4.Cu")
		(net "CLK_100M_OCP_SFF_2_DP")
	)
	(segment
		(start 444.67653 -12.525248)
		(end 444.715138 -12.71905)
		(width 0.14732)
		(layer "In4.Cu")
		(net "CLK_100M_OCP_SFF_2_DP")
	)
	(segment
		(start 437.206136 -21.309076)
		(end 436.993538 -21.82241)
		(width 0.14732)
		(layer "In4.Cu")
		(net "CLK_100M_OCP_SFF_2_DP")
	)
	(segment
		(start 444.018416 -13.510514)
		(end 444.051944 -13.679678)
		(width 0.14732)
		(layer "In4.Cu")
		(net "CLK_100M_OCP_SFF_2_DP")
	)
	(segment
		(start 445.77 -11.864848)
		(end 445.19088 -11.864848)
		(width 0.14732)
		(layer "In4.Cu")
		(net "CLK_100M_OCP_SFF_2_DP")
	)
	(segment
		(start 445.838326 -12.864846)
		(end 446.132966 -12.570206)
		(width 0.14732)
		(layer "In4.Cu")
		(net "CLK_100M_OCP_SFF_2_DP")
	)
	(segment
		(start 444.970408 -12.085574)
		(end 444.67653 -12.525248)
		(width 0.14732)
		(layer "In4.Cu")
		(net "CLK_100M_OCP_SFF_2_DP")
	)
	(segment
		(start 265.207496 -112.093248)
		(end 264.073894 -112.093248)
		(width 0.14732)
		(layer "In4.Cu")
		(net "CLK_100M_OCP_SFF_2_DP")
	)
	(segment
		(start 444.715138 -12.71905)
		(end 444.510668 -13.025374)
		(width 0.14732)
		(layer "In4.Cu")
		(net "CLK_100M_OCP_SFF_2_DP")
	)
	(segment
		(start 446.132966 -12.570206)
		(end 446.132966 -12.227814)
		(width 0.14732)
		(layer "In4.Cu")
		(net "CLK_100M_OCP_SFF_2_DP")
	)
	(segment
		(start 317.095886 -101.940868)
		(end 278.027384 -101.940868)
		(width 0.14732)
		(layer "In4.Cu")
		(net "CLK_100M_OCP_SFF_2_DP")
	)
	(segment
		(start 436.74538 -22.421088)
		(end 434.0733 -28.871926)
		(width 0.14732)
		(layer "In4.Cu")
		(net "CLK_100M_OCP_SFF_2_DP")
	)
	(segment
		(start 443.80912 -14.043152)
		(end 443.639956 -14.076934)
		(width 0.14732)
		(layer "In4.Cu")
		(net "CLK_100M_OCP_SFF_2_DP")
	)
	(segment
		(start 436.92826 -22.34565)
		(end 436.74538 -22.421088)
		(width 0.14732)
		(layer "In4.Cu")
		(net "CLK_100M_OCP_SFF_2_DP")
	)
	(segment
		(start 446.561972 -11.791696)
		(end 446.399666 -11.954002)
		(width 0.13208)
		(layer "F.Cu")
		(net "CLK_100M_OCP_SFF_2_DN")
	)
	(segment
		(start 228.416612 -122.151902)
		(end 228.046026 -122.522488)
		(width 0.13208)
		(layer "F.Cu")
		(net "CLK_100M_OCP_SFF_2_DN")
	)
	(segment
		(start 446.399666 -12.562586)
		(end 446.701926 -12.864846)
		(width 0.13208)
		(layer "F.Cu")
		(net "CLK_100M_OCP_SFF_2_DN")
	)
	(segment
		(start 227.89134 -122.522488)
		(end 227.59924 -122.230388)
		(width 0.13208)
		(layer "F.Cu")
		(net "CLK_100M_OCP_SFF_2_DN")
	)
	(segment
		(start 228.046026 -122.522488)
		(end 227.89134 -122.522488)
		(width 0.13208)
		(layer "F.Cu")
		(net "CLK_100M_OCP_SFF_2_DN")
	)
	(segment
		(start 446.561972 -11.26998)
		(end 446.561972 -11.791696)
		(width 0.13208)
		(layer "F.Cu")
		(net "CLK_100M_OCP_SFF_2_DN")
	)
	(segment
		(start 446.399666 -11.954002)
		(end 446.399666 -12.562586)
		(width 0.13208)
		(layer "F.Cu")
		(net "CLK_100M_OCP_SFF_2_DN")
	)
	(via
		(at 227.59924 -122.230388)
		(size 0.508)
		(drill 0.254)
		(layers "F.Cu" "B.Cu")
		(net "CLK_100M_OCP_SFF_2_DN")
	)
	(via
		(at 446.701926 -12.864846)
		(size 0.508)
		(drill 0.254)
		(layers "F.Cu" "B.Cu")
		(net "CLK_100M_OCP_SFF_2_DN")
	)
	(segment
		(start 277.972774 -101.666548)
		(end 316.982094 -101.666548)
		(width 0.14732)
		(layer "In4.Cu")
		(net "CLK_100M_OCP_SFF_2_DN")
	)
	(segment
		(start 317.855854 -100.792788)
		(end 383.503932 -100.792788)
		(width 0.14732)
		(layer "In4.Cu")
		(net "CLK_100M_OCP_SFF_2_DN")
	)
	(segment
		(start 392.96975 -91.32697)
		(end 400.061684 -74.205592)
		(width 0.14732)
		(layer "In4.Cu")
		(net "CLK_100M_OCP_SFF_2_DN")
	)
	(segment
		(start 433.79898 -47.178214)
		(end 433.79898 -28.817316)
		(width 0.14732)
		(layer "In4.Cu")
		(net "CLK_100M_OCP_SFF_2_DN")
	)
	(segment
		(start 227.59924 -122.230388)
		(end 227.89388 -122.525028)
		(width 0.14732)
		(layer "In4.Cu")
		(net "CLK_100M_OCP_SFF_2_DN")
	)
	(segment
		(start 420.06393 -54.203346)
		(end 426.773848 -54.203346)
		(width 0.14732)
		(layer "In4.Cu")
		(net "CLK_100M_OCP_SFF_2_DN")
	)
	(segment
		(start 273.31797 -103.594662)
		(end 277.972774 -101.666548)
		(width 0.14732)
		(layer "In4.Cu")
		(net "CLK_100M_OCP_SFF_2_DN")
	)
	(segment
		(start 233.257852 -122.525028)
		(end 246.22125 -117.155468)
		(width 0.14732)
		(layer "In4.Cu")
		(net "CLK_100M_OCP_SFF_2_DN")
	)
	(segment
		(start 433.79898 -28.817316)
		(end 437.39054 -20.146772)
		(width 0.14732)
		(layer "In4.Cu")
		(net "CLK_100M_OCP_SFF_2_DN")
	)
	(segment
		(start 246.22125 -117.155468)
		(end 251.135642 -117.155468)
		(width 0.14732)
		(layer "In4.Cu")
		(net "CLK_100M_OCP_SFF_2_DN")
	)
	(segment
		(start 264.019284 -111.818928)
		(end 265.093704 -111.818928)
		(width 0.14732)
		(layer "In4.Cu")
		(net "CLK_100M_OCP_SFF_2_DN")
	)
	(segment
		(start 444.757048 -11.910568)
		(end 445.077088 -11.590528)
		(width 0.14732)
		(layer "In4.Cu")
		(net "CLK_100M_OCP_SFF_2_DN")
	)
	(segment
		(start 446.407286 -12.570206)
		(end 446.701926 -12.864846)
		(width 0.14732)
		(layer "In4.Cu")
		(net "CLK_100M_OCP_SFF_2_DN")
	)
	(segment
		(start 316.982094 -101.666548)
		(end 317.855854 -100.792788)
		(width 0.14732)
		(layer "In4.Cu")
		(net "CLK_100M_OCP_SFF_2_DN")
	)
	(segment
		(start 265.093704 -111.818928)
		(end 273.31797 -103.594662)
		(width 0.14732)
		(layer "In4.Cu")
		(net "CLK_100M_OCP_SFF_2_DN")
	)
	(segment
		(start 446.407286 -12.114022)
		(end 446.407286 -12.570206)
		(width 0.14732)
		(layer "In4.Cu")
		(net "CLK_100M_OCP_SFF_2_DN")
	)
	(segment
		(start 251.135642 -117.155468)
		(end 264.019284 -111.818928)
		(width 0.14732)
		(layer "In4.Cu")
		(net "CLK_100M_OCP_SFF_2_DN")
	)
	(segment
		(start 445.883792 -11.590528)
		(end 446.407286 -12.114022)
		(width 0.14732)
		(layer "In4.Cu")
		(net "CLK_100M_OCP_SFF_2_DN")
	)
	(segment
		(start 437.39054 -20.146772)
		(end 443.00648 -14.530578)
		(width 0.14732)
		(layer "In4.Cu")
		(net "CLK_100M_OCP_SFF_2_DN")
	)
	(segment
		(start 383.503932 -100.792788)
		(end 392.96975 -91.32697)
		(width 0.14732)
		(layer "In4.Cu")
		(net "CLK_100M_OCP_SFF_2_DN")
	)
	(segment
		(start 400.061684 -74.205592)
		(end 420.06393 -54.203346)
		(width 0.14732)
		(layer "In4.Cu")
		(net "CLK_100M_OCP_SFF_2_DN")
	)
	(segment
		(start 443.00648 -14.530578)
		(end 444.757048 -11.910568)
		(width 0.14732)
		(layer "In4.Cu")
		(net "CLK_100M_OCP_SFF_2_DN")
	)
	(segment
		(start 426.773848 -54.203346)
		(end 433.79898 -47.178214)
		(width 0.14732)
		(layer "In4.Cu")
		(net "CLK_100M_OCP_SFF_2_DN")
	)
	(segment
		(start 445.077088 -11.590528)
		(end 445.883792 -11.590528)
		(width 0.14732)
		(layer "In4.Cu")
		(net "CLK_100M_OCP_SFF_2_DN")
	)
	(segment
		(start 227.89388 -122.525028)
		(end 233.257852 -122.525028)
		(width 0.14732)
		(layer "In4.Cu")
		(net "CLK_100M_OCP_SFF_2_DN")
	)
	(segment
		(start 230.1621 -124.950728)
		(end 230.608632 -125.39726)
		(width 0.13208)
		(layer "F.Cu")
		(net "CLK_100M_OCP_SFF_1_R_DP")
	)
	(segment
		(start 229.164642 -125.297946)
		(end 229.51186 -124.950728)
		(width 0.13208)
		(layer "F.Cu")
		(net "CLK_100M_OCP_SFF_1_R_DP")
	)
	(segment
		(start 229.51186 -124.950728)
		(end 230.1621 -124.950728)
		(width 0.13208)
		(layer "F.Cu")
		(net "CLK_100M_OCP_SFF_1_R_DP")
	)
	(segment
		(start 232.127298 -125.39726)
		(end 232.247948 -125.51791)
		(width 0.13208)
		(layer "F.Cu")
		(net "CLK_100M_OCP_SFF_1_R_DP")
	)
	(segment
		(start 230.608632 -125.39726)
		(end 232.127298 -125.39726)
		(width 0.13208)
		(layer "F.Cu")
		(net "CLK_100M_OCP_SFF_1_R_DP")
	)
	(segment
		(start 230.269542 -124.691648)
		(end 230.716074 -125.13818)
		(width 0.13208)
		(layer "F.Cu")
		(net "CLK_100M_OCP_SFF_1_R_DN")
	)
	(segment
		(start 229.164642 -124.281946)
		(end 229.574344 -124.691648)
		(width 0.13208)
		(layer "F.Cu")
		(net "CLK_100M_OCP_SFF_1_R_DN")
	)
	(segment
		(start 229.574344 -124.691648)
		(end 230.269542 -124.691648)
		(width 0.13208)
		(layer "F.Cu")
		(net "CLK_100M_OCP_SFF_1_R_DN")
	)
	(segment
		(start 230.716074 -125.13818)
		(end 232.127552 -125.13818)
		(width 0.13208)
		(layer "F.Cu")
		(net "CLK_100M_OCP_SFF_1_R_DN")
	)
	(segment
		(start 232.127552 -125.13818)
		(end 232.247948 -125.017784)
		(width 0.13208)
		(layer "F.Cu")
		(net "CLK_100M_OCP_SFF_1_R_DN")
	)
	(segment
		(start 431.855118 -6.720586)
		(end 432.15306 -7.018528)
		(width 0.13208)
		(layer "F.Cu")
		(net "CLK_100M_OCP_SFF_1_DP")
	)
	(segment
		(start 431.966878 -7.810246)
		(end 431.966878 -8.320024)
		(width 0.13208)
		(layer "F.Cu")
		(net "CLK_100M_OCP_SFF_1_DP")
	)
	(segment
		(start 227.986082 -124.919486)
		(end 226.219766 -124.919486)
		(width 0.13208)
		(layer "F.Cu")
		(net "CLK_100M_OCP_SFF_1_DP")
	)
	(segment
		(start 432.15306 -7.624064)
		(end 431.966878 -7.810246)
		(width 0.13208)
		(layer "F.Cu")
		(net "CLK_100M_OCP_SFF_1_DP")
	)
	(segment
		(start 432.15306 -7.018528)
		(end 432.15306 -7.624064)
		(width 0.13208)
		(layer "F.Cu")
		(net "CLK_100M_OCP_SFF_1_DP")
	)
	(segment
		(start 226.219766 -124.919486)
		(end 225.917506 -125.221746)
		(width 0.13208)
		(layer "F.Cu")
		(net "CLK_100M_OCP_SFF_1_DP")
	)
	(segment
		(start 228.364542 -125.297946)
		(end 227.986082 -124.919486)
		(width 0.13208)
		(layer "F.Cu")
		(net "CLK_100M_OCP_SFF_1_DP")
	)
	(via
		(at 431.855118 -6.720586)
		(size 0.508)
		(drill 0.254)
		(layers "F.Cu" "B.Cu")
		(net "CLK_100M_OCP_SFF_1_DP")
	)
	(via
		(at 225.917506 -125.221746)
		(size 0.508)
		(drill 0.254)
		(layers "F.Cu" "B.Cu")
		(net "CLK_100M_OCP_SFF_1_DP")
	)
	(segment
		(start 225.622866 -124.927106)
		(end 225.917506 -125.221746)
		(width 0.14732)
		(layer "In4.Cu")
		(net "CLK_100M_OCP_SFF_1_DP")
	)
	(segment
		(start 255.10617 -112.74298)
		(end 241.14506 -112.74298)
		(width 0.14732)
		(layer "In4.Cu")
		(net "CLK_100M_OCP_SFF_1_DP")
	)
	(segment
		(start 430.79924 -19.993102)
		(end 431.24882 -21.078698)
		(width 0.14732)
		(layer "In4.Cu")
		(net "CLK_100M_OCP_SFF_1_DP")
	)
	(segment
		(start 431.24882 -25.010364)
		(end 431.24882 -46.121066)
		(width 0.14732)
		(layer "In4.Cu")
		(net "CLK_100M_OCP_SFF_1_DP")
	)
	(segment
		(start 431.24882 -24.016208)
		(end 431.37836 -24.329136)
		(width 0.14732)
		(layer "In4.Cu")
		(net "CLK_100M_OCP_SFF_1_DP")
	)
	(segment
		(start 430.79924 -18.882868)
		(end 430.79924 -19.993102)
		(width 0.14732)
		(layer "In4.Cu")
		(net "CLK_100M_OCP_SFF_1_DP")
	)
	(segment
		(start 431.24882 -46.121066)
		(end 425.7167 -51.653186)
		(width 0.14732)
		(layer "In4.Cu")
		(net "CLK_100M_OCP_SFF_1_DP")
	)
	(segment
		(start 225.211386 -124.927106)
		(end 225.622866 -124.927106)
		(width 0.14732)
		(layer "In4.Cu")
		(net "CLK_100M_OCP_SFF_1_DP")
	)
	(segment
		(start 430.57318 -14.749018)
		(end 431.57394 -17.164558)
		(width 0.14732)
		(layer "In4.Cu")
		(net "CLK_100M_OCP_SFF_1_DP")
	)
	(segment
		(start 237.514892 -111.2393)
		(end 232.41 -111.2393)
		(width 0.14732)
		(layer "In4.Cu")
		(net "CLK_100M_OCP_SFF_1_DP")
	)
	(segment
		(start 432.149758 -7.015226)
		(end 432.149758 -10.376408)
		(width 0.14732)
		(layer "In4.Cu")
		(net "CLK_100M_OCP_SFF_1_DP")
	)
	(segment
		(start 431.37836 -24.329136)
		(end 431.37836 -24.697436)
		(width 0.14732)
		(layer "In4.Cu")
		(net "CLK_100M_OCP_SFF_1_DP")
	)
	(segment
		(start 317.363602 -96.220788)
		(end 314.280042 -99.304348)
		(width 0.14732)
		(layer "In4.Cu")
		(net "CLK_100M_OCP_SFF_1_DP")
	)
	(segment
		(start 431.855118 -6.720586)
		(end 432.149758 -7.015226)
		(width 0.14732)
		(layer "In4.Cu")
		(net "CLK_100M_OCP_SFF_1_DP")
	)
	(segment
		(start 425.7167 -51.653186)
		(end 419.006782 -51.653186)
		(width 0.14732)
		(layer "In4.Cu")
		(net "CLK_100M_OCP_SFF_1_DP")
	)
	(segment
		(start 396.508986 -74.150982)
		(end 389.417052 -91.27236)
		(width 0.14732)
		(layer "In4.Cu")
		(net "CLK_100M_OCP_SFF_1_DP")
	)
	(segment
		(start 264.372852 -109.456728)
		(end 263.03986 -109.456728)
		(width 0.14732)
		(layer "In4.Cu")
		(net "CLK_100M_OCP_SFF_1_DP")
	)
	(segment
		(start 431.24882 -21.078698)
		(end 431.24882 -24.016208)
		(width 0.14732)
		(layer "In4.Cu")
		(net "CLK_100M_OCP_SFF_1_DP")
	)
	(segment
		(start 431.37836 -24.697436)
		(end 431.24882 -25.010364)
		(width 0.14732)
		(layer "In4.Cu")
		(net "CLK_100M_OCP_SFF_1_DP")
	)
	(segment
		(start 431.57394 -17.164558)
		(end 431.57394 -17.723358)
		(width 0.14732)
		(layer "In4.Cu")
		(net "CLK_100M_OCP_SFF_1_DP")
	)
	(segment
		(start 432.149758 -10.376408)
		(end 430.57318 -11.952986)
		(width 0.14732)
		(layer "In4.Cu")
		(net "CLK_100M_OCP_SFF_1_DP")
	)
	(segment
		(start 384.468624 -96.220788)
		(end 317.363602 -96.220788)
		(width 0.14732)
		(layer "In4.Cu")
		(net "CLK_100M_OCP_SFF_1_DP")
	)
	(segment
		(start 431.57394 -17.723358)
		(end 430.79924 -18.882868)
		(width 0.14732)
		(layer "In4.Cu")
		(net "CLK_100M_OCP_SFF_1_DP")
	)
	(segment
		(start 277.979378 -99.304348)
		(end 272.083022 -101.746558)
		(width 0.14732)
		(layer "In4.Cu")
		(net "CLK_100M_OCP_SFF_1_DP")
	)
	(segment
		(start 263.03986 -109.456728)
		(end 255.10617 -112.74298)
		(width 0.14732)
		(layer "In4.Cu")
		(net "CLK_100M_OCP_SFF_1_DP")
	)
	(segment
		(start 224.460816 -124.176536)
		(end 225.211386 -124.927106)
		(width 0.14732)
		(layer "In4.Cu")
		(net "CLK_100M_OCP_SFF_1_DP")
	)
	(segment
		(start 232.41 -111.2393)
		(end 224.460816 -119.188484)
		(width 0.14732)
		(layer "In4.Cu")
		(net "CLK_100M_OCP_SFF_1_DP")
	)
	(segment
		(start 314.280042 -99.304348)
		(end 277.979378 -99.304348)
		(width 0.14732)
		(layer "In4.Cu")
		(net "CLK_100M_OCP_SFF_1_DP")
	)
	(segment
		(start 224.460816 -119.188484)
		(end 224.460816 -124.176536)
		(width 0.14732)
		(layer "In4.Cu")
		(net "CLK_100M_OCP_SFF_1_DP")
	)
	(segment
		(start 430.57318 -11.952986)
		(end 430.57318 -14.749018)
		(width 0.14732)
		(layer "In4.Cu")
		(net "CLK_100M_OCP_SFF_1_DP")
	)
	(segment
		(start 419.006782 -51.653186)
		(end 396.508986 -74.150982)
		(width 0.14732)
		(layer "In4.Cu")
		(net "CLK_100M_OCP_SFF_1_DP")
	)
	(segment
		(start 241.14506 -112.74298)
		(end 237.514892 -111.2393)
		(width 0.14732)
		(layer "In4.Cu")
		(net "CLK_100M_OCP_SFF_1_DP")
	)
	(segment
		(start 272.083022 -101.746558)
		(end 264.372852 -109.456728)
		(width 0.14732)
		(layer "In4.Cu")
		(net "CLK_100M_OCP_SFF_1_DP")
	)
	(segment
		(start 389.417052 -91.27236)
		(end 384.468624 -96.220788)
		(width 0.14732)
		(layer "In4.Cu")
		(net "CLK_100M_OCP_SFF_1_DP")
	)
	(segment
		(start 227.986082 -124.660406)
		(end 226.219766 -124.660406)
		(width 0.13208)
		(layer "F.Cu")
		(net "CLK_100M_OCP_SFF_1_DN")
	)
	(segment
		(start 432.566826 -7.757414)
		(end 432.41214 -7.602728)
		(width 0.13208)
		(layer "F.Cu")
		(net "CLK_100M_OCP_SFF_1_DN")
	)
	(segment
		(start 432.41214 -7.602728)
		(end 432.41214 -7.027164)
		(width 0.13208)
		(layer "F.Cu")
		(net "CLK_100M_OCP_SFF_1_DN")
	)
	(segment
		(start 432.41214 -7.027164)
		(end 432.718718 -6.720586)
		(width 0.13208)
		(layer "F.Cu")
		(net "CLK_100M_OCP_SFF_1_DN")
	)
	(segment
		(start 432.566826 -8.320024)
		(end 432.566826 -7.757414)
		(width 0.13208)
		(layer "F.Cu")
		(net "CLK_100M_OCP_SFF_1_DN")
	)
	(segment
		(start 228.364542 -124.281946)
		(end 227.986082 -124.660406)
		(width 0.13208)
		(layer "F.Cu")
		(net "CLK_100M_OCP_SFF_1_DN")
	)
	(segment
		(start 226.219766 -124.660406)
		(end 225.917506 -124.358146)
		(width 0.13208)
		(layer "F.Cu")
		(net "CLK_100M_OCP_SFF_1_DN")
	)
	(via
		(at 432.718718 -6.720586)
		(size 0.508)
		(drill 0.254)
		(layers "F.Cu" "B.Cu")
		(net "CLK_100M_OCP_SFF_1_DN")
	)
	(via
		(at 225.917506 -124.358146)
		(size 0.508)
		(drill 0.254)
		(layers "F.Cu" "B.Cu")
		(net "CLK_100M_OCP_SFF_1_DN")
	)
	(segment
		(start 224.867216 -123.208288)
		(end 224.735136 -123.340368)
		(width 0.14732)
		(layer "In4.Cu")
		(net "CLK_100M_OCP_SFF_1_DN")
	)
	(segment
		(start 432.718718 -6.720586)
		(end 432.424078 -7.015226)
		(width 0.14732)
		(layer "In4.Cu")
		(net "CLK_100M_OCP_SFF_1_DN")
	)
	(segment
		(start 224.735136 -122.715528)
		(end 224.867216 -122.847608)
		(width 0.14732)
		(layer "In4.Cu")
		(net "CLK_100M_OCP_SFF_1_DN")
	)
	(segment
		(start 225.527362 -118.69674)
		(end 225.340672 -118.69674)
		(width 0.14732)
		(layer "In4.Cu")
		(net "CLK_100M_OCP_SFF_1_DN")
	)
	(segment
		(start 241.09045 -113.0173)
		(end 237.460282 -111.51362)
		(width 0.14732)
		(layer "In4.Cu")
		(net "CLK_100M_OCP_SFF_1_DN")
	)
	(segment
		(start 314.393834 -99.578668)
		(end 278.033988 -99.578668)
		(width 0.14732)
		(layer "In4.Cu")
		(net "CLK_100M_OCP_SFF_1_DN")
	)
	(segment
		(start 224.735136 -121.369328)
		(end 224.735136 -121.730008)
		(width 0.14732)
		(layer "In4.Cu")
		(net "CLK_100M_OCP_SFF_1_DN")
	)
	(segment
		(start 431.52314 -46.234858)
		(end 425.830492 -51.927506)
		(width 0.14732)
		(layer "In4.Cu")
		(net "CLK_100M_OCP_SFF_1_DN")
	)
	(segment
		(start 431.65268 -24.752046)
		(end 431.52314 -25.064974)
		(width 0.14732)
		(layer "In4.Cu")
		(net "CLK_100M_OCP_SFF_1_DN")
	)
	(segment
		(start 272.23847 -101.979222)
		(end 264.486644 -109.731048)
		(width 0.14732)
		(layer "In4.Cu")
		(net "CLK_100M_OCP_SFF_1_DN")
	)
	(segment
		(start 431.84826 -17.80667)
		(end 431.07356 -18.96618)
		(width 0.14732)
		(layer "In4.Cu")
		(net "CLK_100M_OCP_SFF_1_DN")
	)
	(segment
		(start 425.830492 -51.927506)
		(end 419.120574 -51.927506)
		(width 0.14732)
		(layer "In4.Cu")
		(net "CLK_100M_OCP_SFF_1_DN")
	)
	(segment
		(start 224.867216 -122.847608)
		(end 224.867216 -123.208288)
		(width 0.14732)
		(layer "In4.Cu")
		(net "CLK_100M_OCP_SFF_1_DN")
	)
	(segment
		(start 232.523792 -111.51362)
		(end 225.782632 -118.25478)
		(width 0.14732)
		(layer "In4.Cu")
		(net "CLK_100M_OCP_SFF_1_DN")
	)
	(segment
		(start 224.735136 -122.354848)
		(end 224.735136 -122.715528)
		(width 0.14732)
		(layer "In4.Cu")
		(net "CLK_100M_OCP_SFF_1_DN")
	)
	(segment
		(start 278.033988 -99.578668)
		(end 272.23847 -101.979222)
		(width 0.14732)
		(layer "In4.Cu")
		(net "CLK_100M_OCP_SFF_1_DN")
	)
	(segment
		(start 430.8475 -12.066778)
		(end 430.8475 -14.694408)
		(width 0.14732)
		(layer "In4.Cu")
		(net "CLK_100M_OCP_SFF_1_DN")
	)
	(segment
		(start 431.65268 -24.274526)
		(end 431.65268 -24.752046)
		(width 0.14732)
		(layer "In4.Cu")
		(net "CLK_100M_OCP_SFF_1_DN")
	)
	(segment
		(start 224.735136 -124.062744)
		(end 225.325178 -124.652786)
		(width 0.14732)
		(layer "In4.Cu")
		(net "CLK_100M_OCP_SFF_1_DN")
	)
	(segment
		(start 225.782632 -118.25478)
		(end 225.782632 -118.44147)
		(width 0.14732)
		(layer "In4.Cu")
		(net "CLK_100M_OCP_SFF_1_DN")
	)
	(segment
		(start 225.622866 -124.652786)
		(end 225.917506 -124.358146)
		(width 0.14732)
		(layer "In4.Cu")
		(net "CLK_100M_OCP_SFF_1_DN")
	)
	(segment
		(start 431.07356 -19.938492)
		(end 431.52314 -21.024088)
		(width 0.14732)
		(layer "In4.Cu")
		(net "CLK_100M_OCP_SFF_1_DN")
	)
	(segment
		(start 224.735136 -121.730008)
		(end 224.867216 -121.862088)
		(width 0.14732)
		(layer "In4.Cu")
		(net "CLK_100M_OCP_SFF_1_DN")
	)
	(segment
		(start 255.16078 -113.0173)
		(end 241.09045 -113.0173)
		(width 0.14732)
		(layer "In4.Cu")
		(net "CLK_100M_OCP_SFF_1_DN")
	)
	(segment
		(start 225.340672 -118.69674)
		(end 224.735136 -119.302276)
		(width 0.14732)
		(layer "In4.Cu")
		(net "CLK_100M_OCP_SFF_1_DN")
	)
	(segment
		(start 431.07356 -18.96618)
		(end 431.07356 -19.938492)
		(width 0.14732)
		(layer "In4.Cu")
		(net "CLK_100M_OCP_SFF_1_DN")
	)
	(segment
		(start 225.782632 -118.44147)
		(end 225.527362 -118.69674)
		(width 0.14732)
		(layer "In4.Cu")
		(net "CLK_100M_OCP_SFF_1_DN")
	)
	(segment
		(start 224.735136 -123.340368)
		(end 224.735136 -124.062744)
		(width 0.14732)
		(layer "In4.Cu")
		(net "CLK_100M_OCP_SFF_1_DN")
	)
	(segment
		(start 432.424078 -7.015226)
		(end 432.424078 -10.4902)
		(width 0.14732)
		(layer "In4.Cu")
		(net "CLK_100M_OCP_SFF_1_DN")
	)
	(segment
		(start 431.52314 -21.024088)
		(end 431.52314 -23.961598)
		(width 0.14732)
		(layer "In4.Cu")
		(net "CLK_100M_OCP_SFF_1_DN")
	)
	(segment
		(start 224.867216 -121.862088)
		(end 224.867216 -122.222768)
		(width 0.14732)
		(layer "In4.Cu")
		(net "CLK_100M_OCP_SFF_1_DN")
	)
	(segment
		(start 431.84826 -17.109948)
		(end 431.84826 -17.80667)
		(width 0.14732)
		(layer "In4.Cu")
		(net "CLK_100M_OCP_SFF_1_DN")
	)
	(segment
		(start 237.460282 -111.51362)
		(end 232.523792 -111.51362)
		(width 0.14732)
		(layer "In4.Cu")
		(net "CLK_100M_OCP_SFF_1_DN")
	)
	(segment
		(start 384.582416 -96.495108)
		(end 317.477394 -96.495108)
		(width 0.14732)
		(layer "In4.Cu")
		(net "CLK_100M_OCP_SFF_1_DN")
	)
	(segment
		(start 224.867216 -120.876568)
		(end 224.867216 -121.237248)
		(width 0.14732)
		(layer "In4.Cu")
		(net "CLK_100M_OCP_SFF_1_DN")
	)
	(segment
		(start 224.735136 -119.302276)
		(end 224.735136 -120.744488)
		(width 0.14732)
		(layer "In4.Cu")
		(net "CLK_100M_OCP_SFF_1_DN")
	)
	(segment
		(start 419.120574 -51.927506)
		(end 396.74165 -74.30643)
		(width 0.14732)
		(layer "In4.Cu")
		(net "CLK_100M_OCP_SFF_1_DN")
	)
	(segment
		(start 317.477394 -96.495108)
		(end 314.393834 -99.578668)
		(width 0.14732)
		(layer "In4.Cu")
		(net "CLK_100M_OCP_SFF_1_DN")
	)
	(segment
		(start 396.74165 -74.30643)
		(end 389.649716 -91.427808)
		(width 0.14732)
		(layer "In4.Cu")
		(net "CLK_100M_OCP_SFF_1_DN")
	)
	(segment
		(start 225.325178 -124.652786)
		(end 225.622866 -124.652786)
		(width 0.14732)
		(layer "In4.Cu")
		(net "CLK_100M_OCP_SFF_1_DN")
	)
	(segment
		(start 224.735136 -120.744488)
		(end 224.867216 -120.876568)
		(width 0.14732)
		(layer "In4.Cu")
		(net "CLK_100M_OCP_SFF_1_DN")
	)
	(segment
		(start 431.52314 -25.064974)
		(end 431.52314 -46.234858)
		(width 0.14732)
		(layer "In4.Cu")
		(net "CLK_100M_OCP_SFF_1_DN")
	)
	(segment
		(start 430.8475 -14.694408)
		(end 431.84826 -17.109948)
		(width 0.14732)
		(layer "In4.Cu")
		(net "CLK_100M_OCP_SFF_1_DN")
	)
	(segment
		(start 389.649716 -91.427808)
		(end 384.582416 -96.495108)
		(width 0.14732)
		(layer "In4.Cu")
		(net "CLK_100M_OCP_SFF_1_DN")
	)
	(segment
		(start 224.867216 -121.237248)
		(end 224.735136 -121.369328)
		(width 0.14732)
		(layer "In4.Cu")
		(net "CLK_100M_OCP_SFF_1_DN")
	)
	(segment
		(start 224.867216 -122.222768)
		(end 224.735136 -122.354848)
		(width 0.14732)
		(layer "In4.Cu")
		(net "CLK_100M_OCP_SFF_1_DN")
	)
	(segment
		(start 432.424078 -10.4902)
		(end 430.8475 -12.066778)
		(width 0.14732)
		(layer "In4.Cu")
		(net "CLK_100M_OCP_SFF_1_DN")
	)
	(segment
		(start 263.09447 -109.731048)
		(end 255.16078 -113.0173)
		(width 0.14732)
		(layer "In4.Cu")
		(net "CLK_100M_OCP_SFF_1_DN")
	)
	(segment
		(start 431.52314 -23.961598)
		(end 431.65268 -24.274526)
		(width 0.14732)
		(layer "In4.Cu")
		(net "CLK_100M_OCP_SFF_1_DN")
	)
	(segment
		(start 264.486644 -109.731048)
		(end 263.09447 -109.731048)
		(width 0.14732)
		(layer "In4.Cu")
		(net "CLK_100M_OCP_SFF_1_DN")
	)
	(segment
		(start 230.408734 -127.029718)
		(end 230.538528 -126.899924)
		(width 0.13208)
		(layer "F.Cu")
		(net "CLK_100M_OCP_SFF_0_R_DP")
	)
	(segment
		(start 230.538528 -126.899924)
		(end 232.130092 -126.899924)
		(width 0.13208)
		(layer "F.Cu")
		(net "CLK_100M_OCP_SFF_0_R_DP")
	)
	(segment
		(start 232.130092 -126.899924)
		(end 232.247948 -127.01778)
		(width 0.13208)
		(layer "F.Cu")
		(net "CLK_100M_OCP_SFF_0_R_DP")
	)
	(segment
		(start 229.530656 -127.029718)
		(end 230.408734 -127.029718)
		(width 0.13208)
		(layer "F.Cu")
		(net "CLK_100M_OCP_SFF_0_R_DP")
	)
	(segment
		(start 229.160832 -127.399542)
		(end 229.530656 -127.029718)
		(width 0.13208)
		(layer "F.Cu")
		(net "CLK_100M_OCP_SFF_0_R_DP")
	)
	(segment
		(start 232.247948 -126.517908)
		(end 232.125012 -126.640844)
		(width 0.13208)
		(layer "F.Cu")
		(net "CLK_100M_OCP_SFF_0_R_DN")
	)
	(segment
		(start 230.301292 -126.770638)
		(end 229.547928 -126.770638)
		(width 0.13208)
		(layer "F.Cu")
		(net "CLK_100M_OCP_SFF_0_R_DN")
	)
	(segment
		(start 230.431086 -126.640844)
		(end 230.301292 -126.770638)
		(width 0.13208)
		(layer "F.Cu")
		(net "CLK_100M_OCP_SFF_0_R_DN")
	)
	(segment
		(start 232.125012 -126.640844)
		(end 230.431086 -126.640844)
		(width 0.13208)
		(layer "F.Cu")
		(net "CLK_100M_OCP_SFF_0_R_DN")
	)
	(segment
		(start 229.547928 -126.770638)
		(end 229.160832 -126.383542)
		(width 0.13208)
		(layer "F.Cu")
		(net "CLK_100M_OCP_SFF_0_R_DN")
	)
	(segment
		(start 227.41636 -127.323342)
		(end 227.41636 -127.325628)
		(width 0.13208)
		(layer "F.Cu")
		(net "CLK_100M_OCP_SFF_0_DP")
	)
	(segment
		(start 432.14544 -11.966702)
		(end 432.14544 -12.562586)
		(width 0.13208)
		(layer "F.Cu")
		(net "CLK_100M_OCP_SFF_0_DP")
	)
	(segment
		(start 228.360732 -127.399542)
		(end 227.974398 -127.013208)
		(width 0.13208)
		(layer "F.Cu")
		(net "CLK_100M_OCP_SFF_0_DP")
	)
	(segment
		(start 432.14544 -12.562586)
		(end 431.84318 -12.864846)
		(width 0.13208)
		(layer "F.Cu")
		(net "CLK_100M_OCP_SFF_0_DP")
	)
	(segment
		(start 227.974398 -127.013208)
		(end 227.726494 -127.013208)
		(width 0.13208)
		(layer "F.Cu")
		(net "CLK_100M_OCP_SFF_0_DP")
	)
	(segment
		(start 431.966878 -11.78814)
		(end 432.14544 -11.966702)
		(width 0.13208)
		(layer "F.Cu")
		(net "CLK_100M_OCP_SFF_0_DP")
	)
	(segment
		(start 431.966878 -11.26998)
		(end 431.966878 -11.78814)
		(width 0.13208)
		(layer "F.Cu")
		(net "CLK_100M_OCP_SFF_0_DP")
	)
	(segment
		(start 227.726494 -127.013208)
		(end 227.41636 -127.323342)
		(width 0.13208)
		(layer "F.Cu")
		(net "CLK_100M_OCP_SFF_0_DP")
	)
	(via
		(at 227.41636 -127.325628)
		(size 0.508)
		(drill 0.254)
		(layers "F.Cu" "B.Cu")
		(net "CLK_100M_OCP_SFF_0_DP")
	)
	(via
		(at 431.84318 -12.864846)
		(size 0.508)
		(drill 0.254)
		(layers "F.Cu" "B.Cu")
		(net "CLK_100M_OCP_SFF_0_DP")
	)
	(segment
		(start 278.179022 -100.305108)
		(end 272.650204 -102.595172)
		(width 0.14732)
		(layer "In4.Cu")
		(net "CLK_100M_OCP_SFF_0_DP")
	)
	(segment
		(start 397.900652 -74.440796)
		(end 390.808718 -91.562174)
		(width 0.14732)
		(layer "In4.Cu")
		(net "CLK_100M_OCP_SFF_0_DP")
	)
	(segment
		(start 390.808718 -91.562174)
		(end 383.312924 -99.057968)
		(width 0.14732)
		(layer "In4.Cu")
		(net "CLK_100M_OCP_SFF_0_DP")
	)
	(segment
		(start 237.312708 -112.393984)
		(end 233.021124 -112.393984)
		(width 0.14732)
		(layer "In4.Cu")
		(net "CLK_100M_OCP_SFF_0_DP")
	)
	(segment
		(start 226.24288 -123.396756)
		(end 228.341174 -125.49505)
		(width 0.14732)
		(layer "In4.Cu")
		(net "CLK_100M_OCP_SFF_0_DP")
	)
	(segment
		(start 434.235352 -20.35683)
		(end 434.088286 -20.576794)
		(width 0.14732)
		(layer "In4.Cu")
		(net "CLK_100M_OCP_SFF_0_DP")
	)
	(segment
		(start 426.20946 -52.841906)
		(end 419.499542 -52.841906)
		(width 0.14732)
		(layer "In4.Cu")
		(net "CLK_100M_OCP_SFF_0_DP")
	)
	(segment
		(start 315.11494 -100.305108)
		(end 278.179022 -100.305108)
		(width 0.14732)
		(layer "In4.Cu")
		(net "CLK_100M_OCP_SFF_0_DP")
	)
	(segment
		(start 233.021124 -112.393984)
		(end 226.81184 -118.603268)
		(width 0.14732)
		(layer "In4.Cu")
		(net "CLK_100M_OCP_SFF_0_DP")
	)
	(segment
		(start 435.00802 -11.323828)
		(end 435.28996 -11.605768)
		(width 0.14732)
		(layer "In4.Cu")
		(net "CLK_100M_OCP_SFF_0_DP")
	)
	(segment
		(start 434.088286 -20.576794)
		(end 433.565554 -21.838666)
		(width 0.14732)
		(layer "In4.Cu")
		(net "CLK_100M_OCP_SFF_0_DP")
	)
	(segment
		(start 226.81184 -121.07418)
		(end 226.24288 -121.64314)
		(width 0.14732)
		(layer "In4.Cu")
		(net "CLK_100M_OCP_SFF_0_DP")
	)
	(segment
		(start 226.81184 -118.603268)
		(end 226.81184 -121.07418)
		(width 0.14732)
		(layer "In4.Cu")
		(net "CLK_100M_OCP_SFF_0_DP")
	)
	(segment
		(start 435.28996 -11.605768)
		(end 435.28996 -19.302222)
		(width 0.14732)
		(layer "In4.Cu")
		(net "CLK_100M_OCP_SFF_0_DP")
	)
	(segment
		(start 254.559816 -114.117374)
		(end 241.473482 -114.117374)
		(width 0.14732)
		(layer "In4.Cu")
		(net "CLK_100M_OCP_SFF_0_DP")
	)
	(segment
		(start 226.24288 -121.64314)
		(end 226.24288 -123.396756)
		(width 0.14732)
		(layer "In4.Cu")
		(net "CLK_100M_OCP_SFF_0_DP")
	)
	(segment
		(start 272.650204 -102.595172)
		(end 264.787888 -110.457488)
		(width 0.14732)
		(layer "In4.Cu")
		(net "CLK_100M_OCP_SFF_0_DP")
	)
	(segment
		(start 435.28996 -19.302222)
		(end 434.235352 -20.35683)
		(width 0.14732)
		(layer "In4.Cu")
		(net "CLK_100M_OCP_SFF_0_DP")
	)
	(segment
		(start 228.341174 -125.49505)
		(end 228.341174 -126.72314)
		(width 0.14732)
		(layer "In4.Cu")
		(net "CLK_100M_OCP_SFF_0_DP")
	)
	(segment
		(start 432.43754 -27.50947)
		(end 432.43754 -46.613826)
		(width 0.14732)
		(layer "In4.Cu")
		(net "CLK_100M_OCP_SFF_0_DP")
	)
	(segment
		(start 432.13782 -12.570206)
		(end 432.13782 -12.012676)
		(width 0.14732)
		(layer "In4.Cu")
		(net "CLK_100M_OCP_SFF_0_DP")
	)
	(segment
		(start 432.13782 -12.012676)
		(end 432.826668 -11.323828)
		(width 0.14732)
		(layer "In4.Cu")
		(net "CLK_100M_OCP_SFF_0_DP")
	)
	(segment
		(start 228.341174 -126.72314)
		(end 228.033326 -127.030988)
		(width 0.14732)
		(layer "In4.Cu")
		(net "CLK_100M_OCP_SFF_0_DP")
	)
	(segment
		(start 432.43754 -46.613826)
		(end 426.20946 -52.841906)
		(width 0.14732)
		(layer "In4.Cu")
		(net "CLK_100M_OCP_SFF_0_DP")
	)
	(segment
		(start 419.499542 -52.841906)
		(end 397.900652 -74.440796)
		(width 0.14732)
		(layer "In4.Cu")
		(net "CLK_100M_OCP_SFF_0_DP")
	)
	(segment
		(start 263.395714 -110.457488)
		(end 254.559816 -114.117374)
		(width 0.14732)
		(layer "In4.Cu")
		(net "CLK_100M_OCP_SFF_0_DP")
	)
	(segment
		(start 227.711 -127.030988)
		(end 227.41636 -127.325628)
		(width 0.14732)
		(layer "In4.Cu")
		(net "CLK_100M_OCP_SFF_0_DP")
	)
	(segment
		(start 432.826668 -11.323828)
		(end 435.00802 -11.323828)
		(width 0.14732)
		(layer "In4.Cu")
		(net "CLK_100M_OCP_SFF_0_DP")
	)
	(segment
		(start 228.033326 -127.030988)
		(end 227.711 -127.030988)
		(width 0.14732)
		(layer "In4.Cu")
		(net "CLK_100M_OCP_SFF_0_DP")
	)
	(segment
		(start 241.473482 -114.117374)
		(end 237.312708 -112.393984)
		(width 0.14732)
		(layer "In4.Cu")
		(net "CLK_100M_OCP_SFF_0_DP")
	)
	(segment
		(start 316.36208 -99.057968)
		(end 315.11494 -100.305108)
		(width 0.14732)
		(layer "In4.Cu")
		(net "CLK_100M_OCP_SFF_0_DP")
	)
	(segment
		(start 264.787888 -110.457488)
		(end 263.395714 -110.457488)
		(width 0.14732)
		(layer "In4.Cu")
		(net "CLK_100M_OCP_SFF_0_DP")
	)
	(segment
		(start 383.312924 -99.057968)
		(end 316.36208 -99.057968)
		(width 0.14732)
		(layer "In4.Cu")
		(net "CLK_100M_OCP_SFF_0_DP")
	)
	(segment
		(start 431.84318 -12.864846)
		(end 432.13782 -12.570206)
		(width 0.14732)
		(layer "In4.Cu")
		(net "CLK_100M_OCP_SFF_0_DP")
	)
	(segment
		(start 433.565554 -21.838666)
		(end 432.43754 -27.50947)
		(width 0.14732)
		(layer "In4.Cu")
		(net "CLK_100M_OCP_SFF_0_DP")
	)
	(segment
		(start 227.70846 -126.754128)
		(end 227.41636 -126.462028)
		(width 0.13208)
		(layer "F.Cu")
		(net "CLK_100M_OCP_SFF_0_DN")
	)
	(segment
		(start 227.990146 -126.754128)
		(end 227.70846 -126.754128)
		(width 0.13208)
		(layer "F.Cu")
		(net "CLK_100M_OCP_SFF_0_DN")
	)
	(segment
		(start 432.566826 -11.26998)
		(end 432.566826 -11.791696)
		(width 0.13208)
		(layer "F.Cu")
		(net "CLK_100M_OCP_SFF_0_DN")
	)
	(segment
		(start 228.360732 -126.383542)
		(end 227.990146 -126.754128)
		(width 0.13208)
		(layer "F.Cu")
		(net "CLK_100M_OCP_SFF_0_DN")
	)
	(segment
		(start 432.40452 -12.562586)
		(end 432.70678 -12.864846)
		(width 0.13208)
		(layer "F.Cu")
		(net "CLK_100M_OCP_SFF_0_DN")
	)
	(segment
		(start 432.40452 -11.954002)
		(end 432.40452 -12.562586)
		(width 0.13208)
		(layer "F.Cu")
		(net "CLK_100M_OCP_SFF_0_DN")
	)
	(segment
		(start 432.566826 -11.791696)
		(end 432.40452 -11.954002)
		(width 0.13208)
		(layer "F.Cu")
		(net "CLK_100M_OCP_SFF_0_DN")
	)
	(via
		(at 432.70678 -12.864846)
		(size 0.508)
		(drill 0.254)
		(layers "F.Cu" "B.Cu")
		(net "CLK_100M_OCP_SFF_0_DN")
	)
	(via
		(at 227.41636 -126.462028)
		(size 0.508)
		(drill 0.254)
		(layers "F.Cu" "B.Cu")
		(net "CLK_100M_OCP_SFF_0_DN")
	)
	(segment
		(start 433.229512 -22.12086)
		(end 433.06492 -22.230588)
		(width 0.14732)
		(layer "In4.Cu")
		(net "CLK_100M_OCP_SFF_0_DN")
	)
	(segment
		(start 435.01564 -18.172176)
		(end 434.87594 -18.311876)
		(width 0.14732)
		(layer "In4.Cu")
		(net "CLK_100M_OCP_SFF_0_DN")
	)
	(segment
		(start 254.505206 -113.843054)
		(end 241.528092 -113.843054)
		(width 0.14732)
		(layer "In4.Cu")
		(net "CLK_100M_OCP_SFF_0_DN")
	)
	(segment
		(start 432.39817 -25.582118)
		(end 432.507898 -25.746456)
		(width 0.14732)
		(layer "In4.Cu")
		(net "CLK_100M_OCP_SFF_0_DN")
	)
	(segment
		(start 226.53752 -120.592088)
		(end 226.53752 -120.960388)
		(width 0.14732)
		(layer "In4.Cu")
		(net "CLK_100M_OCP_SFF_0_DN")
	)
	(segment
		(start 227.010722 -124.750322)
		(end 227.271326 -125.010926)
		(width 0.14732)
		(layer "In4.Cu")
		(net "CLK_100M_OCP_SFF_0_DN")
	)
	(segment
		(start 227.271326 -125.010926)
		(end 227.468938 -125.010926)
		(width 0.14732)
		(layer "In4.Cu")
		(net "CLK_100M_OCP_SFF_0_DN")
	)
	(segment
		(start 434.88102 -17.676876)
		(end 435.01564 -17.811496)
		(width 0.14732)
		(layer "In4.Cu")
		(net "CLK_100M_OCP_SFF_0_DN")
	)
	(segment
		(start 227.468938 -125.010926)
		(end 228.066854 -125.608842)
		(width 0.14732)
		(layer "In4.Cu")
		(net "CLK_100M_OCP_SFF_0_DN")
	)
	(segment
		(start 435.01564 -11.71956)
		(end 435.01564 -17.181576)
		(width 0.14732)
		(layer "In4.Cu")
		(net "CLK_100M_OCP_SFF_0_DN")
	)
	(segment
		(start 228.066854 -126.609348)
		(end 227.919534 -126.756668)
		(width 0.14732)
		(layer "In4.Cu")
		(net "CLK_100M_OCP_SFF_0_DN")
	)
	(segment
		(start 426.095668 -52.567586)
		(end 419.38575 -52.567586)
		(width 0.14732)
		(layer "In4.Cu")
		(net "CLK_100M_OCP_SFF_0_DN")
	)
	(segment
		(start 433.509928 -21.255482)
		(end 433.30114 -21.759672)
		(width 0.14732)
		(layer "In4.Cu")
		(net "CLK_100M_OCP_SFF_0_DN")
	)
	(segment
		(start 225.82886 -122.442478)
		(end 225.82886 -122.810778)
		(width 0.14732)
		(layer "In4.Cu")
		(net "CLK_100M_OCP_SFF_0_DN")
	)
	(segment
		(start 226.39782 -120.452388)
		(end 226.53752 -120.592088)
		(width 0.14732)
		(layer "In4.Cu")
		(net "CLK_100M_OCP_SFF_0_DN")
	)
	(segment
		(start 432.309778 -26.743152)
		(end 432.16322 -27.481022)
		(width 0.14732)
		(layer "In4.Cu")
		(net "CLK_100M_OCP_SFF_0_DN")
	)
	(segment
		(start 397.667988 -74.285348)
		(end 390.576054 -91.406726)
		(width 0.14732)
		(layer "In4.Cu")
		(net "CLK_100M_OCP_SFF_0_DN")
	)
	(segment
		(start 226.39782 -120.084088)
		(end 226.39782 -120.452388)
		(width 0.14732)
		(layer "In4.Cu")
		(net "CLK_100M_OCP_SFF_0_DN")
	)
	(segment
		(start 435.01564 -17.181576)
		(end 434.88102 -17.316196)
		(width 0.14732)
		(layer "In4.Cu")
		(net "CLK_100M_OCP_SFF_0_DN")
	)
	(segment
		(start 432.20005 -26.578814)
		(end 432.309778 -26.743152)
		(width 0.14732)
		(layer "In4.Cu")
		(net "CLK_100M_OCP_SFF_0_DN")
	)
	(segment
		(start 433.102766 -22.756368)
		(end 433.031138 -23.117556)
		(width 0.14732)
		(layer "In4.Cu")
		(net "CLK_100M_OCP_SFF_0_DN")
	)
	(segment
		(start 433.575206 -20.732496)
		(end 433.434236 -21.07311)
		(width 0.14732)
		(layer "In4.Cu")
		(net "CLK_100M_OCP_SFF_0_DN")
	)
	(segment
		(start 433.844954 -20.446746)
		(end 433.758086 -20.656804)
		(width 0.14732)
		(layer "In4.Cu")
		(net "CLK_100M_OCP_SFF_0_DN")
	)
	(segment
		(start 432.16322 -46.500034)
		(end 426.095668 -52.567586)
		(width 0.14732)
		(layer "In4.Cu")
		(net "CLK_100M_OCP_SFF_0_DN")
	)
	(segment
		(start 241.528092 -113.843054)
		(end 237.367318 -112.119664)
		(width 0.14732)
		(layer "In4.Cu")
		(net "CLK_100M_OCP_SFF_0_DN")
	)
	(segment
		(start 225.96856 -123.510548)
		(end 227.010722 -124.55271)
		(width 0.14732)
		(layer "In4.Cu")
		(net "CLK_100M_OCP_SFF_0_DN")
	)
	(segment
		(start 434.87594 -18.311876)
		(end 434.87594 -18.680176)
		(width 0.14732)
		(layer "In4.Cu")
		(net "CLK_100M_OCP_SFF_0_DN")
	)
	(segment
		(start 432.70678 -12.864846)
		(end 432.41214 -12.570206)
		(width 0.14732)
		(layer "In4.Cu")
		(net "CLK_100M_OCP_SFF_0_DN")
	)
	(segment
		(start 432.993038 -22.59203)
		(end 433.102766 -22.756368)
		(width 0.14732)
		(layer "In4.Cu")
		(net "CLK_100M_OCP_SFF_0_DN")
	)
	(segment
		(start 432.470052 -25.220676)
		(end 432.39817 -25.582118)
		(width 0.14732)
		(layer "In4.Cu")
		(net "CLK_100M_OCP_SFF_0_DN")
	)
	(segment
		(start 434.88102 -17.316196)
		(end 434.88102 -17.676876)
		(width 0.14732)
		(layer "In4.Cu")
		(net "CLK_100M_OCP_SFF_0_DN")
	)
	(segment
		(start 237.367318 -112.119664)
		(end 232.907332 -112.119664)
		(width 0.14732)
		(layer "In4.Cu")
		(net "CLK_100M_OCP_SFF_0_DN")
	)
	(segment
		(start 433.434236 -21.07311)
		(end 433.509928 -21.255482)
		(width 0.14732)
		(layer "In4.Cu")
		(net "CLK_100M_OCP_SFF_0_DN")
	)
	(segment
		(start 226.53752 -118.489476)
		(end 226.53752 -119.944388)
		(width 0.14732)
		(layer "In4.Cu")
		(net "CLK_100M_OCP_SFF_0_DN")
	)
	(segment
		(start 225.96856 -122.950478)
		(end 225.96856 -123.510548)
		(width 0.14732)
		(layer "In4.Cu")
		(net "CLK_100M_OCP_SFF_0_DN")
	)
	(segment
		(start 390.576054 -91.406726)
		(end 383.199132 -98.783648)
		(width 0.14732)
		(layer "In4.Cu")
		(net "CLK_100M_OCP_SFF_0_DN")
	)
	(segment
		(start 225.96856 -122.302778)
		(end 225.82886 -122.442478)
		(width 0.14732)
		(layer "In4.Cu")
		(net "CLK_100M_OCP_SFF_0_DN")
	)
	(segment
		(start 435.01564 -17.811496)
		(end 435.01564 -18.172176)
		(width 0.14732)
		(layer "In4.Cu")
		(net "CLK_100M_OCP_SFF_0_DN")
	)
	(segment
		(start 432.832764 -24.114252)
		(end 432.668172 -24.22398)
		(width 0.14732)
		(layer "In4.Cu")
		(net "CLK_100M_OCP_SFF_0_DN")
	)
	(segment
		(start 434.87594 -18.680176)
		(end 435.01564 -18.819876)
		(width 0.14732)
		(layer "In4.Cu")
		(net "CLK_100M_OCP_SFF_0_DN")
	)
	(segment
		(start 432.634644 -25.110948)
		(end 432.470052 -25.220676)
		(width 0.14732)
		(layer "In4.Cu")
		(net "CLK_100M_OCP_SFF_0_DN")
	)
	(segment
		(start 227.711 -126.756668)
		(end 227.41636 -126.462028)
		(width 0.14732)
		(layer "In4.Cu")
		(net "CLK_100M_OCP_SFF_0_DN")
	)
	(segment
		(start 432.43627 -26.107644)
		(end 432.271678 -26.217372)
		(width 0.14732)
		(layer "In4.Cu")
		(net "CLK_100M_OCP_SFF_0_DN")
	)
	(segment
		(start 432.94046 -11.598148)
		(end 434.894228 -11.598148)
		(width 0.14732)
		(layer "In4.Cu")
		(net "CLK_100M_OCP_SFF_0_DN")
	)
	(segment
		(start 263.341104 -110.183168)
		(end 254.505206 -113.843054)
		(width 0.14732)
		(layer "In4.Cu")
		(net "CLK_100M_OCP_SFF_0_DN")
	)
	(segment
		(start 278.124412 -100.030788)
		(end 272.494756 -102.362508)
		(width 0.14732)
		(layer "In4.Cu")
		(net "CLK_100M_OCP_SFF_0_DN")
	)
	(segment
		(start 432.59629 -24.585422)
		(end 432.706272 -24.74976)
		(width 0.14732)
		(layer "In4.Cu")
		(net "CLK_100M_OCP_SFF_0_DN")
	)
	(segment
		(start 435.01564 -18.819876)
		(end 435.01564 -19.188176)
		(width 0.14732)
		(layer "In4.Cu")
		(net "CLK_100M_OCP_SFF_0_DN")
	)
	(segment
		(start 272.494756 -102.362508)
		(end 264.674096 -110.183168)
		(width 0.14732)
		(layer "In4.Cu")
		(net "CLK_100M_OCP_SFF_0_DN")
	)
	(segment
		(start 433.30114 -21.759672)
		(end 433.229512 -22.12086)
		(width 0.14732)
		(layer "In4.Cu")
		(net "CLK_100M_OCP_SFF_0_DN")
	)
	(segment
		(start 432.794664 -23.588726)
		(end 432.904392 -23.753064)
		(width 0.14732)
		(layer "In4.Cu")
		(net "CLK_100M_OCP_SFF_0_DN")
	)
	(segment
		(start 432.866546 -23.227284)
		(end 432.794664 -23.588726)
		(width 0.14732)
		(layer "In4.Cu")
		(net "CLK_100M_OCP_SFF_0_DN")
	)
	(segment
		(start 226.53752 -120.960388)
		(end 225.96856 -121.529348)
		(width 0.14732)
		(layer "In4.Cu")
		(net "CLK_100M_OCP_SFF_0_DN")
	)
	(segment
		(start 434.65496 -19.548856)
		(end 434.457348 -19.548856)
		(width 0.14732)
		(layer "In4.Cu")
		(net "CLK_100M_OCP_SFF_0_DN")
	)
	(segment
		(start 432.507898 -25.746456)
		(end 432.43627 -26.107644)
		(width 0.14732)
		(layer "In4.Cu")
		(net "CLK_100M_OCP_SFF_0_DN")
	)
	(segment
		(start 433.031138 -23.117556)
		(end 432.866546 -23.227284)
		(width 0.14732)
		(layer "In4.Cu")
		(net "CLK_100M_OCP_SFF_0_DN")
	)
	(segment
		(start 434.021992 -20.181824)
		(end 433.844954 -20.446746)
		(width 0.14732)
		(layer "In4.Cu")
		(net "CLK_100M_OCP_SFF_0_DN")
	)
	(segment
		(start 225.82886 -122.810778)
		(end 225.96856 -122.950478)
		(width 0.14732)
		(layer "In4.Cu")
		(net "CLK_100M_OCP_SFF_0_DN")
	)
	(segment
		(start 383.199132 -98.783648)
		(end 316.248288 -98.783648)
		(width 0.14732)
		(layer "In4.Cu")
		(net "CLK_100M_OCP_SFF_0_DN")
	)
	(segment
		(start 227.919534 -126.756668)
		(end 227.711 -126.756668)
		(width 0.14732)
		(layer "In4.Cu")
		(net "CLK_100M_OCP_SFF_0_DN")
	)
	(segment
		(start 434.894228 -11.598148)
		(end 435.01564 -11.71956)
		(width 0.14732)
		(layer "In4.Cu")
		(net "CLK_100M_OCP_SFF_0_DN")
	)
	(segment
		(start 315.001148 -100.030788)
		(end 278.124412 -100.030788)
		(width 0.14732)
		(layer "In4.Cu")
		(net "CLK_100M_OCP_SFF_0_DN")
	)
	(segment
		(start 225.96856 -121.529348)
		(end 225.96856 -122.302778)
		(width 0.14732)
		(layer "In4.Cu")
		(net "CLK_100M_OCP_SFF_0_DN")
	)
	(segment
		(start 432.271678 -26.217372)
		(end 432.20005 -26.578814)
		(width 0.14732)
		(layer "In4.Cu")
		(net "CLK_100M_OCP_SFF_0_DN")
	)
	(segment
		(start 434.457348 -19.548856)
		(end 434.196744 -19.80946)
		(width 0.14732)
		(layer "In4.Cu")
		(net "CLK_100M_OCP_SFF_0_DN")
	)
	(segment
		(start 226.53752 -119.944388)
		(end 226.39782 -120.084088)
		(width 0.14732)
		(layer "In4.Cu")
		(net "CLK_100M_OCP_SFF_0_DN")
	)
	(segment
		(start 264.674096 -110.183168)
		(end 263.341104 -110.183168)
		(width 0.14732)
		(layer "In4.Cu")
		(net "CLK_100M_OCP_SFF_0_DN")
	)
	(segment
		(start 434.196744 -20.007072)
		(end 434.021992 -20.181824)
		(width 0.14732)
		(layer "In4.Cu")
		(net "CLK_100M_OCP_SFF_0_DN")
	)
	(segment
		(start 228.066854 -125.608842)
		(end 228.066854 -126.609348)
		(width 0.14732)
		(layer "In4.Cu")
		(net "CLK_100M_OCP_SFF_0_DN")
	)
	(segment
		(start 434.196744 -19.80946)
		(end 434.196744 -20.007072)
		(width 0.14732)
		(layer "In4.Cu")
		(net "CLK_100M_OCP_SFF_0_DN")
	)
	(segment
		(start 432.668172 -24.22398)
		(end 432.59629 -24.585422)
		(width 0.14732)
		(layer "In4.Cu")
		(net "CLK_100M_OCP_SFF_0_DN")
	)
	(segment
		(start 432.904392 -23.753064)
		(end 432.832764 -24.114252)
		(width 0.14732)
		(layer "In4.Cu")
		(net "CLK_100M_OCP_SFF_0_DN")
	)
	(segment
		(start 316.248288 -98.783648)
		(end 315.001148 -100.030788)
		(width 0.14732)
		(layer "In4.Cu")
		(net "CLK_100M_OCP_SFF_0_DN")
	)
	(segment
		(start 432.706272 -24.74976)
		(end 432.634644 -25.110948)
		(width 0.14732)
		(layer "In4.Cu")
		(net "CLK_100M_OCP_SFF_0_DN")
	)
	(segment
		(start 419.38575 -52.567586)
		(end 397.667988 -74.285348)
		(width 0.14732)
		(layer "In4.Cu")
		(net "CLK_100M_OCP_SFF_0_DN")
	)
	(segment
		(start 433.758086 -20.656804)
		(end 433.575206 -20.732496)
		(width 0.14732)
		(layer "In4.Cu")
		(net "CLK_100M_OCP_SFF_0_DN")
	)
	(segment
		(start 435.01564 -19.188176)
		(end 434.65496 -19.548856)
		(width 0.14732)
		(layer "In4.Cu")
		(net "CLK_100M_OCP_SFF_0_DN")
	)
	(segment
		(start 232.907332 -112.119664)
		(end 226.53752 -118.489476)
		(width 0.14732)
		(layer "In4.Cu")
		(net "CLK_100M_OCP_SFF_0_DN")
	)
	(segment
		(start 432.41214 -12.570206)
		(end 432.41214 -12.126468)
		(width 0.14732)
		(layer "In4.Cu")
		(net "CLK_100M_OCP_SFF_0_DN")
	)
	(segment
		(start 433.06492 -22.230588)
		(end 432.993038 -22.59203)
		(width 0.14732)
		(layer "In4.Cu")
		(net "CLK_100M_OCP_SFF_0_DN")
	)
	(segment
		(start 432.41214 -12.126468)
		(end 432.94046 -11.598148)
		(width 0.14732)
		(layer "In4.Cu")
		(net "CLK_100M_OCP_SFF_0_DN")
	)
	(segment
		(start 227.010722 -124.55271)
		(end 227.010722 -124.750322)
		(width 0.14732)
		(layer "In4.Cu")
		(net "CLK_100M_OCP_SFF_0_DN")
	)
	(segment
		(start 432.16322 -27.481022)
		(end 432.16322 -46.500034)
		(width 0.14732)
		(layer "In4.Cu")
		(net "CLK_100M_OCP_SFF_0_DN")
	)
	(segment
		(start 259.860034 -98.707448)
		(end 259.860796 -98.70821)
		(width 0.13208)
		(layer "F.Cu")
		(net "CLK_100M_DB2000_DP")
	)
	(segment
		(start 238.956342 -127.1397)
		(end 237.869984 -127.1397)
		(width 0.13208)
		(layer "F.Cu")
		(net "CLK_100M_DB2000_DP")
	)
	(segment
		(start 259.741416 -98.813112)
		(end 259.84708 -98.707448)
		(width 0.13208)
		(layer "F.Cu")
		(net "CLK_100M_DB2000_DP")
	)
	(segment
		(start 260.299962 -98.707448)
		(end 260.975602 -98.031808)
		(width 0.13208)
		(layer "F.Cu")
		(net "CLK_100M_DB2000_DP")
	)
	(segment
		(start 237.869984 -127.1397)
		(end 237.748064 -127.01778)
		(width 0.13208)
		(layer "F.Cu")
		(net "CLK_100M_DB2000_DP")
	)
	(segment
		(start 261.805674 -98.031808)
		(end 262.1153 -98.341434)
		(width 0.13208)
		(layer "F.Cu")
		(net "CLK_100M_DB2000_DP")
	)
	(segment
		(start 259.861812 -98.70821)
		(end 259.862574 -98.707448)
		(width 0.13208)
		(layer "F.Cu")
		(net "CLK_100M_DB2000_DP")
	)
	(segment
		(start 239.992916 -126.581408)
		(end 239.772698 -126.801626)
		(width 0.13208)
		(layer "F.Cu")
		(net "CLK_100M_DB2000_DP")
	)
	(segment
		(start 260.975602 -98.031808)
		(end 261.805674 -98.031808)
		(width 0.13208)
		(layer "F.Cu")
		(net "CLK_100M_DB2000_DP")
	)
	(segment
		(start 242.42268 -126.276608)
		(end 242.11788 -126.581408)
		(width 0.13208)
		(layer "F.Cu")
		(net "CLK_100M_DB2000_DP")
	)
	(segment
		(start 259.84708 -98.707448)
		(end 259.860034 -98.707448)
		(width 0.13208)
		(layer "F.Cu")
		(net "CLK_100M_DB2000_DP")
	)
	(segment
		(start 239.772698 -126.801626)
		(end 238.956342 -127.1397)
		(width 0.13208)
		(layer "F.Cu")
		(net "CLK_100M_DB2000_DP")
	)
	(segment
		(start 242.11788 -126.581408)
		(end 239.992916 -126.581408)
		(width 0.13208)
		(layer "F.Cu")
		(net "CLK_100M_DB2000_DP")
	)
	(segment
		(start 259.862574 -98.707448)
		(end 260.299962 -98.707448)
		(width 0.13208)
		(layer "F.Cu")
		(net "CLK_100M_DB2000_DP")
	)
	(segment
		(start 259.860796 -98.70821)
		(end 259.861812 -98.70821)
		(width 0.13208)
		(layer "F.Cu")
		(net "CLK_100M_DB2000_DP")
	)
	(segment
		(start 259.557774 -98.813112)
		(end 259.741416 -98.813112)
		(width 0.13208)
		(layer "F.Cu")
		(net "CLK_100M_DB2000_DP")
	)
	(via
		(at 242.42268 -126.276608)
		(size 0.508)
		(drill 0.254)
		(layers "F.Cu" "B.Cu")
		(net "CLK_100M_DB2000_DP")
	)
	(via
		(at 262.1153 -98.341434)
		(size 0.508)
		(drill 0.254)
		(layers "F.Cu" "B.Cu")
		(net "CLK_100M_DB2000_DP")
	)
	(segment
		(start 255.112012 -117.953028)
		(end 257.502152 -120.865138)
		(width 0.14732)
		(layer "In2.Cu")
		(net "CLK_100M_DB2000_DP")
	)
	(segment
		(start 242.42268 -126.276608)
		(end 242.71732 -126.571248)
		(width 0.14732)
		(layer "In2.Cu")
		(net "CLK_100M_DB2000_DP")
	)
	(segment
		(start 262.13816 -109.6899)
		(end 262.13816 -107.984544)
		(width 0.14732)
		(layer "In2.Cu")
		(net "CLK_100M_DB2000_DP")
	)
	(segment
		(start 249.865134 -122.259598)
		(end 249.907806 -121.826528)
		(width 0.14732)
		(layer "In2.Cu")
		(net "CLK_100M_DB2000_DP")
	)
	(segment
		(start 260.585966 -118.524528)
		(end 260.865112 -118.29542)
		(width 0.14732)
		(layer "In2.Cu")
		(net "CLK_100M_DB2000_DP")
	)
	(segment
		(start 261.68858 -103.642922)
		(end 261.83336 -103.498142)
		(width 0.14732)
		(layer "In2.Cu")
		(net "CLK_100M_DB2000_DP")
	)
	(segment
		(start 262.249158 -100.067872)
		(end 262.72236 -98.92538)
		(width 0.14732)
		(layer "In2.Cu")
		(net "CLK_100M_DB2000_DP")
	)
	(segment
		(start 259.147564 -119.70512)
		(end 259.42671 -119.476012)
		(width 0.14732)
		(layer "In2.Cu")
		(net "CLK_100M_DB2000_DP")
	)
	(segment
		(start 254.18034 -118.717822)
		(end 254.223012 -118.284752)
		(width 0.14732)
		(layer "In2.Cu")
		(net "CLK_100M_DB2000_DP")
	)
	(segment
		(start 257.556 -115.549172)
		(end 257.988816 -115.591844)
		(width 0.14732)
		(layer "In2.Cu")
		(net "CLK_100M_DB2000_DP")
	)
	(segment
		(start 252.255274 -125.171708)
		(end 249.865134 -122.259598)
		(width 0.14732)
		(layer "In2.Cu")
		(net "CLK_100M_DB2000_DP")
	)
	(segment
		(start 261.99719 -100.675694)
		(end 261.918704 -100.486718)
		(width 0.14732)
		(layer "In2.Cu")
		(net "CLK_100M_DB2000_DP")
	)
	(segment
		(start 251.303536 -121.079006)
		(end 251.346208 -120.645936)
		(width 0.14732)
		(layer "In2.Cu")
		(net "CLK_100M_DB2000_DP")
	)
	(segment
		(start 253.186946 -124.406914)
		(end 253.393956 -124.427488)
		(width 0.14732)
		(layer "In2.Cu")
		(net "CLK_100M_DB2000_DP")
	)
	(segment
		(start 252.2347 -125.378972)
		(end 252.255274 -125.171708)
		(width 0.14732)
		(layer "In2.Cu")
		(net "CLK_100M_DB2000_DP")
	)
	(segment
		(start 261.918704 -100.486718)
		(end 262.059674 -100.146104)
		(width 0.14732)
		(layer "In2.Cu")
		(net "CLK_100M_DB2000_DP")
	)
	(segment
		(start 246.506492 -124.617988)
		(end 248.925588 -122.632724)
		(width 0.14732)
		(layer "In2.Cu")
		(net "CLK_100M_DB2000_DP")
	)
	(segment
		(start 252.235208 -120.314212)
		(end 254.625348 -123.226322)
		(width 0.14732)
		(layer "In2.Cu")
		(net "CLK_100M_DB2000_DP")
	)
	(segment
		(start 258.940554 -119.684546)
		(end 259.147564 -119.70512)
		(width 0.14732)
		(layer "In2.Cu")
		(net "CLK_100M_DB2000_DP")
	)
	(segment
		(start 258.534408 -114.782092)
		(end 261.05358 -112.71504)
		(width 0.14732)
		(layer "In2.Cu")
		(net "CLK_100M_DB2000_DP")
	)
	(segment
		(start 244.7163 -125.899926)
		(end 244.920008 -125.919992)
		(width 0.14732)
		(layer "In2.Cu")
		(net "CLK_100M_DB2000_DP")
	)
	(segment
		(start 251.955554 -125.60808)
		(end 252.2347 -125.378972)
		(width 0.14732)
		(layer "In2.Cu")
		(net "CLK_100M_DB2000_DP")
	)
	(segment
		(start 262.40994 -98.046794)
		(end 262.1153 -98.341434)
		(width 0.14732)
		(layer "In2.Cu")
		(net "CLK_100M_DB2000_DP")
	)
	(segment
		(start 245.71325 -125.26899)
		(end 245.99773 -125.035564)
		(width 0.14732)
		(layer "In2.Cu")
		(net "CLK_100M_DB2000_DP")
	)
	(segment
		(start 246.302784 -124.597922)
		(end 246.506492 -124.617988)
		(width 0.14732)
		(layer "In2.Cu")
		(net "CLK_100M_DB2000_DP")
	)
	(segment
		(start 251.748544 -125.587506)
		(end 251.955554 -125.60808)
		(width 0.14732)
		(layer "In2.Cu")
		(net "CLK_100M_DB2000_DP")
	)
	(segment
		(start 260.378956 -118.503954)
		(end 260.585966 -118.524528)
		(width 0.14732)
		(layer "In2.Cu")
		(net "CLK_100M_DB2000_DP")
	)
	(segment
		(start 254.625348 -123.226322)
		(end 254.832358 -123.246896)
		(width 0.14732)
		(layer "In2.Cu")
		(net "CLK_100M_DB2000_DP")
	)
	(segment
		(start 251.346208 -120.645936)
		(end 251.802392 -120.27154)
		(width 0.14732)
		(layer "In2.Cu")
		(net "CLK_100M_DB2000_DP")
	)
	(segment
		(start 257.709162 -120.885712)
		(end 257.988308 -120.656604)
		(width 0.14732)
		(layer "In2.Cu")
		(net "CLK_100M_DB2000_DP")
	)
	(segment
		(start 262.72236 -98.19894)
		(end 262.570214 -98.046794)
		(width 0.14732)
		(layer "In2.Cu")
		(net "CLK_100M_DB2000_DP")
	)
	(segment
		(start 248.925588 -122.632724)
		(end 249.358404 -122.675396)
		(width 0.14732)
		(layer "In2.Cu")
		(net "CLK_100M_DB2000_DP")
	)
	(segment
		(start 261.68858 -104.011222)
		(end 261.68858 -103.642922)
		(width 0.14732)
		(layer "In2.Cu")
		(net "CLK_100M_DB2000_DP")
	)
	(segment
		(start 257.502152 -120.865138)
		(end 257.709162 -120.885712)
		(width 0.14732)
		(layer "In2.Cu")
		(net "CLK_100M_DB2000_DP")
	)
	(segment
		(start 244.411246 -126.337822)
		(end 244.431312 -126.13386)
		(width 0.14732)
		(layer "In2.Cu")
		(net "CLK_100M_DB2000_DP")
	)
	(segment
		(start 258.495546 -115.176046)
		(end 258.534408 -114.782092)
		(width 0.14732)
		(layer "In2.Cu")
		(net "CLK_100M_DB2000_DP")
	)
	(segment
		(start 255.618742 -117.53723)
		(end 255.661414 -117.10416)
		(width 0.14732)
		(layer "In2.Cu")
		(net "CLK_100M_DB2000_DP")
	)
	(segment
		(start 249.907806 -121.826528)
		(end 250.36399 -121.452132)
		(width 0.14732)
		(layer "In2.Cu")
		(net "CLK_100M_DB2000_DP")
	)
	(segment
		(start 261.83336 -104.878378)
		(end 261.83336 -104.156002)
		(width 0.14732)
		(layer "In2.Cu")
		(net "CLK_100M_DB2000_DP")
	)
	(segment
		(start 259.42671 -119.476012)
		(end 259.447284 -119.268748)
		(width 0.14732)
		(layer "In2.Cu")
		(net "CLK_100M_DB2000_DP")
	)
	(segment
		(start 262.72236 -98.92538)
		(end 262.72236 -98.19894)
		(width 0.14732)
		(layer "In2.Cu")
		(net "CLK_100M_DB2000_DP")
	)
	(segment
		(start 262.570214 -98.046794)
		(end 262.40994 -98.046794)
		(width 0.14732)
		(layer "In2.Cu")
		(net "CLK_100M_DB2000_DP")
	)
	(segment
		(start 256.549906 -121.837196)
		(end 256.57048 -121.629932)
		(width 0.14732)
		(layer "In2.Cu")
		(net "CLK_100M_DB2000_DP")
	)
	(segment
		(start 257.057144 -116.356638)
		(end 257.099816 -115.923568)
		(width 0.14732)
		(layer "In2.Cu")
		(net "CLK_100M_DB2000_DP")
	)
	(segment
		(start 253.67361 -119.13362)
		(end 256.06375 -122.04573)
		(width 0.14732)
		(layer "In2.Cu")
		(net "CLK_100M_DB2000_DP")
	)
	(segment
		(start 255.111504 -123.017788)
		(end 255.132078 -122.810524)
		(width 0.14732)
		(layer "In2.Cu")
		(net "CLK_100M_DB2000_DP")
	)
	(segment
		(start 256.550414 -116.772436)
		(end 258.940554 -119.684546)
		(width 0.14732)
		(layer "In2.Cu")
		(net "CLK_100M_DB2000_DP")
	)
	(segment
		(start 261.68858 -101.590602)
		(end 261.83336 -101.445822)
		(width 0.14732)
		(layer "In2.Cu")
		(net "CLK_100M_DB2000_DP")
	)
	(segment
		(start 255.132078 -122.810524)
		(end 252.741938 -119.898414)
		(width 0.14732)
		(layer "In2.Cu")
		(net "CLK_100M_DB2000_DP")
	)
	(segment
		(start 253.393956 -124.427488)
		(end 253.673102 -124.19838)
		(width 0.14732)
		(layer "In2.Cu")
		(net "CLK_100M_DB2000_DP")
	)
	(segment
		(start 245.204488 -125.686566)
		(end 245.224554 -125.482604)
		(width 0.14732)
		(layer "In2.Cu")
		(net "CLK_100M_DB2000_DP")
	)
	(segment
		(start 261.83336 -104.156002)
		(end 261.68858 -104.011222)
		(width 0.14732)
		(layer "In2.Cu")
		(net "CLK_100M_DB2000_DP")
	)
	(segment
		(start 259.447284 -119.268748)
		(end 257.057144 -116.356638)
		(width 0.14732)
		(layer "In2.Cu")
		(net "CLK_100M_DB2000_DP")
	)
	(segment
		(start 251.802392 -120.27154)
		(end 252.235208 -120.314212)
		(width 0.14732)
		(layer "In2.Cu")
		(net "CLK_100M_DB2000_DP")
	)
	(segment
		(start 252.78461 -119.465344)
		(end 253.240794 -119.090948)
		(width 0.14732)
		(layer "In2.Cu")
		(net "CLK_100M_DB2000_DP")
	)
	(segment
		(start 261.05358 -112.71504)
		(end 261.615936 -111.95685)
		(width 0.14732)
		(layer "In2.Cu")
		(net "CLK_100M_DB2000_DP")
	)
	(segment
		(start 257.099816 -115.923568)
		(end 257.556 -115.549172)
		(width 0.14732)
		(layer "In2.Cu")
		(net "CLK_100M_DB2000_DP")
	)
	(segment
		(start 261.83336 -102.471982)
		(end 261.83336 -102.103682)
		(width 0.14732)
		(layer "In2.Cu")
		(net "CLK_100M_DB2000_DP")
	)
	(segment
		(start 245.224554 -125.482604)
		(end 245.509542 -125.248924)
		(width 0.14732)
		(layer "In2.Cu")
		(net "CLK_100M_DB2000_DP")
	)
	(segment
		(start 262.059674 -100.146104)
		(end 262.249158 -100.067872)
		(width 0.14732)
		(layer "In2.Cu")
		(net "CLK_100M_DB2000_DP")
	)
	(segment
		(start 249.358404 -122.675396)
		(end 251.748544 -125.587506)
		(width 0.14732)
		(layer "In2.Cu")
		(net "CLK_100M_DB2000_DP")
	)
	(segment
		(start 244.431312 -126.13386)
		(end 244.7163 -125.899926)
		(width 0.14732)
		(layer "In2.Cu")
		(net "CLK_100M_DB2000_DP")
	)
	(segment
		(start 262.116062 -110.750096)
		(end 262.13816 -109.6899)
		(width 0.14732)
		(layer "In2.Cu")
		(net "CLK_100M_DB2000_DP")
	)
	(segment
		(start 242.71732 -126.571248)
		(end 244.126766 -126.571248)
		(width 0.14732)
		(layer "In2.Cu")
		(net "CLK_100M_DB2000_DP")
	)
	(segment
		(start 256.57048 -121.629932)
		(end 254.18034 -118.717822)
		(width 0.14732)
		(layer "In2.Cu")
		(net "CLK_100M_DB2000_DP")
	)
	(segment
		(start 253.240794 -119.090948)
		(end 253.67361 -119.13362)
		(width 0.14732)
		(layer "In2.Cu")
		(net "CLK_100M_DB2000_DP")
	)
	(segment
		(start 255.661414 -117.10416)
		(end 256.117598 -116.729764)
		(width 0.14732)
		(layer "In2.Cu")
		(net "CLK_100M_DB2000_DP")
	)
	(segment
		(start 254.832358 -123.246896)
		(end 255.111504 -123.017788)
		(width 0.14732)
		(layer "In2.Cu")
		(net "CLK_100M_DB2000_DP")
	)
	(segment
		(start 261.83336 -103.129842)
		(end 261.68858 -102.985062)
		(width 0.14732)
		(layer "In2.Cu")
		(net "CLK_100M_DB2000_DP")
	)
	(segment
		(start 261.83336 -103.498142)
		(end 261.83336 -103.129842)
		(width 0.14732)
		(layer "In2.Cu")
		(net "CLK_100M_DB2000_DP")
	)
	(segment
		(start 257.988816 -115.591844)
		(end 260.378956 -118.503954)
		(width 0.14732)
		(layer "In2.Cu")
		(net "CLK_100M_DB2000_DP")
	)
	(segment
		(start 258.008882 -120.44934)
		(end 255.618742 -117.53723)
		(width 0.14732)
		(layer "In2.Cu")
		(net "CLK_100M_DB2000_DP")
	)
	(segment
		(start 256.06375 -122.04573)
		(end 256.27076 -122.066304)
		(width 0.14732)
		(layer "In2.Cu")
		(net "CLK_100M_DB2000_DP")
	)
	(segment
		(start 257.988308 -120.656604)
		(end 258.008882 -120.44934)
		(width 0.14732)
		(layer "In2.Cu")
		(net "CLK_100M_DB2000_DP")
	)
	(segment
		(start 261.68858 -102.616762)
		(end 261.83336 -102.471982)
		(width 0.14732)
		(layer "In2.Cu")
		(net "CLK_100M_DB2000_DP")
	)
	(segment
		(start 250.796806 -121.494804)
		(end 253.186946 -124.406914)
		(width 0.14732)
		(layer "In2.Cu")
		(net "CLK_100M_DB2000_DP")
	)
	(segment
		(start 245.509542 -125.248924)
		(end 245.71325 -125.26899)
		(width 0.14732)
		(layer "In2.Cu")
		(net "CLK_100M_DB2000_DP")
	)
	(segment
		(start 256.27076 -122.066304)
		(end 256.549906 -121.837196)
		(width 0.14732)
		(layer "In2.Cu")
		(net "CLK_100M_DB2000_DP")
	)
	(segment
		(start 244.920008 -125.919992)
		(end 245.204488 -125.686566)
		(width 0.14732)
		(layer "In2.Cu")
		(net "CLK_100M_DB2000_DP")
	)
	(segment
		(start 253.673102 -124.19838)
		(end 253.693676 -123.991116)
		(width 0.14732)
		(layer "In2.Cu")
		(net "CLK_100M_DB2000_DP")
	)
	(segment
		(start 261.615936 -111.95685)
		(end 262.116062 -110.750096)
		(width 0.14732)
		(layer "In2.Cu")
		(net "CLK_100M_DB2000_DP")
	)
	(segment
		(start 252.741938 -119.898414)
		(end 252.78461 -119.465344)
		(width 0.14732)
		(layer "In2.Cu")
		(net "CLK_100M_DB2000_DP")
	)
	(segment
		(start 261.83336 -102.103682)
		(end 261.68858 -101.958902)
		(width 0.14732)
		(layer "In2.Cu")
		(net "CLK_100M_DB2000_DP")
	)
	(segment
		(start 244.126766 -126.571248)
		(end 244.411246 -126.337822)
		(width 0.14732)
		(layer "In2.Cu")
		(net "CLK_100M_DB2000_DP")
	)
	(segment
		(start 260.865112 -118.29542)
		(end 260.885686 -118.088156)
		(width 0.14732)
		(layer "In2.Cu")
		(net "CLK_100M_DB2000_DP")
	)
	(segment
		(start 256.117598 -116.729764)
		(end 256.550414 -116.772436)
		(width 0.14732)
		(layer "In2.Cu")
		(net "CLK_100M_DB2000_DP")
	)
	(segment
		(start 254.223012 -118.284752)
		(end 254.679196 -117.910356)
		(width 0.14732)
		(layer "In2.Cu")
		(net "CLK_100M_DB2000_DP")
	)
	(segment
		(start 246.017796 -124.831602)
		(end 246.302784 -124.597922)
		(width 0.14732)
		(layer "In2.Cu")
		(net "CLK_100M_DB2000_DP")
	)
	(segment
		(start 261.83336 -101.445822)
		(end 261.83336 -101.071172)
		(width 0.14732)
		(layer "In2.Cu")
		(net "CLK_100M_DB2000_DP")
	)
	(segment
		(start 245.99773 -125.035564)
		(end 246.017796 -124.831602)
		(width 0.14732)
		(layer "In2.Cu")
		(net "CLK_100M_DB2000_DP")
	)
	(segment
		(start 261.68858 -101.958902)
		(end 261.68858 -101.590602)
		(width 0.14732)
		(layer "In2.Cu")
		(net "CLK_100M_DB2000_DP")
	)
	(segment
		(start 261.68858 -102.985062)
		(end 261.68858 -102.616762)
		(width 0.14732)
		(layer "In2.Cu")
		(net "CLK_100M_DB2000_DP")
	)
	(segment
		(start 250.36399 -121.452132)
		(end 250.796806 -121.494804)
		(width 0.14732)
		(layer "In2.Cu")
		(net "CLK_100M_DB2000_DP")
	)
	(segment
		(start 261.83336 -101.071172)
		(end 261.99719 -100.675694)
		(width 0.14732)
		(layer "In2.Cu")
		(net "CLK_100M_DB2000_DP")
	)
	(segment
		(start 262.13816 -107.984544)
		(end 261.83336 -104.878378)
		(width 0.14732)
		(layer "In2.Cu")
		(net "CLK_100M_DB2000_DP")
	)
	(segment
		(start 253.693676 -123.991116)
		(end 251.303536 -121.079006)
		(width 0.14732)
		(layer "In2.Cu")
		(net "CLK_100M_DB2000_DP")
	)
	(segment
		(start 260.885686 -118.088156)
		(end 258.495546 -115.176046)
		(width 0.14732)
		(layer "In2.Cu")
		(net "CLK_100M_DB2000_DP")
	)
	(segment
		(start 254.679196 -117.910356)
		(end 255.112012 -117.953028)
		(width 0.14732)
		(layer "In2.Cu")
		(net "CLK_100M_DB2000_DP")
	)
	(segment
		(start 239.007904 -127.39878)
		(end 239.91951 -127.021336)
		(width 0.13208)
		(layer "F.Cu")
		(net "CLK_100M_DB2000_DN")
	)
	(segment
		(start 237.86719 -127.39878)
		(end 239.007904 -127.39878)
		(width 0.13208)
		(layer "F.Cu")
		(net "CLK_100M_DB2000_DN")
	)
	(segment
		(start 259.862574 -98.448368)
		(end 260.19252 -98.448368)
		(width 0.13208)
		(layer "F.Cu")
		(net "CLK_100M_DB2000_DN")
	)
	(segment
		(start 261.820406 -97.772728)
		(end 262.1153 -97.477834)
		(width 0.13208)
		(layer "F.Cu")
		(net "CLK_100M_DB2000_DN")
	)
	(segment
		(start 237.748064 -127.517906)
		(end 237.86719 -127.39878)
		(width 0.13208)
		(layer "F.Cu")
		(net "CLK_100M_DB2000_DN")
	)
	(segment
		(start 259.727446 -98.31324)
		(end 259.862574 -98.448368)
		(width 0.13208)
		(layer "F.Cu")
		(net "CLK_100M_DB2000_DN")
	)
	(segment
		(start 260.86816 -97.772728)
		(end 261.820406 -97.772728)
		(width 0.13208)
		(layer "F.Cu")
		(net "CLK_100M_DB2000_DN")
	)
	(segment
		(start 242.12296 -126.840488)
		(end 242.42268 -127.140208)
		(width 0.13208)
		(layer "F.Cu")
		(net "CLK_100M_DB2000_DN")
	)
	(segment
		(start 240.100358 -126.840488)
		(end 242.12296 -126.840488)
		(width 0.13208)
		(layer "F.Cu")
		(net "CLK_100M_DB2000_DN")
	)
	(segment
		(start 259.557774 -98.31324)
		(end 259.727446 -98.31324)
		(width 0.13208)
		(layer "F.Cu")
		(net "CLK_100M_DB2000_DN")
	)
	(segment
		(start 260.19252 -98.448368)
		(end 260.86816 -97.772728)
		(width 0.13208)
		(layer "F.Cu")
		(net "CLK_100M_DB2000_DN")
	)
	(segment
		(start 239.91951 -127.021336)
		(end 240.100358 -126.840488)
		(width 0.13208)
		(layer "F.Cu")
		(net "CLK_100M_DB2000_DN")
	)
	(via
		(at 242.42268 -127.140208)
		(size 0.508)
		(drill 0.254)
		(layers "F.Cu" "B.Cu")
		(net "CLK_100M_DB2000_DN")
	)
	(via
		(at 262.1153 -97.477834)
		(size 0.508)
		(drill 0.254)
		(layers "F.Cu" "B.Cu")
		(net "CLK_100M_DB2000_DN")
	)
	(segment
		(start 257.848862 -115.853718)
		(end 260.239002 -118.765828)
		(width 0.14732)
		(layer "In2.Cu")
		(net "CLK_100M_DB2000_DN")
	)
	(segment
		(start 254.485394 -123.488196)
		(end 254.918464 -123.531376)
		(width 0.14732)
		(layer "In2.Cu")
		(net "CLK_100M_DB2000_DN")
	)
	(segment
		(start 251.888498 -120.555766)
		(end 252.095254 -120.576086)
		(width 0.14732)
		(layer "In2.Cu")
		(net "CLK_100M_DB2000_DN")
	)
	(segment
		(start 253.977902 -123.90501)
		(end 251.587762 -120.9929)
		(width 0.14732)
		(layer "In2.Cu")
		(net "CLK_100M_DB2000_DN")
	)
	(segment
		(start 251.587762 -120.9929)
		(end 251.608336 -120.786144)
		(width 0.14732)
		(layer "In2.Cu")
		(net "CLK_100M_DB2000_DN")
	)
	(segment
		(start 252.496574 -125.518926)
		(end 252.5395 -125.085602)
		(width 0.14732)
		(layer "In2.Cu")
		(net "CLK_100M_DB2000_DN")
	)
	(segment
		(start 255.416304 -122.724418)
		(end 253.026164 -119.812308)
		(width 0.14732)
		(layer "In2.Cu")
		(net "CLK_100M_DB2000_DN")
	)
	(segment
		(start 256.81178 -121.97715)
		(end 256.854706 -121.543826)
		(width 0.14732)
		(layer "In2.Cu")
		(net "CLK_100M_DB2000_DN")
	)
	(segment
		(start 251.608336 -120.786144)
		(end 251.888498 -120.555766)
		(width 0.14732)
		(layer "In2.Cu")
		(net "CLK_100M_DB2000_DN")
	)
	(segment
		(start 249.21845 -122.93727)
		(end 251.60859 -125.84938)
		(width 0.14732)
		(layer "In2.Cu")
		(net "CLK_100M_DB2000_DN")
	)
	(segment
		(start 252.095254 -120.576086)
		(end 254.485394 -123.488196)
		(width 0.14732)
		(layer "In2.Cu")
		(net "CLK_100M_DB2000_DN")
	)
	(segment
		(start 251.60859 -125.84938)
		(end 252.04166 -125.89256)
		(width 0.14732)
		(layer "In2.Cu")
		(net "CLK_100M_DB2000_DN")
	)
	(segment
		(start 262.10768 -101.125782)
		(end 262.99668 -98.97999)
		(width 0.14732)
		(layer "In2.Cu")
		(net "CLK_100M_DB2000_DN")
	)
	(segment
		(start 262.389366 -110.8075)
		(end 262.41248 -109.692948)
		(width 0.14732)
		(layer "In2.Cu")
		(net "CLK_100M_DB2000_DN")
	)
	(segment
		(start 260.239002 -118.765828)
		(end 260.672072 -118.809008)
		(width 0.14732)
		(layer "In2.Cu")
		(net "CLK_100M_DB2000_DN")
	)
	(segment
		(start 252.04166 -125.89256)
		(end 252.496574 -125.518926)
		(width 0.14732)
		(layer "In2.Cu")
		(net "CLK_100M_DB2000_DN")
	)
	(segment
		(start 258.293108 -120.363234)
		(end 255.902968 -117.451124)
		(width 0.14732)
		(layer "In2.Cu")
		(net "CLK_100M_DB2000_DN")
	)
	(segment
		(start 254.48514 -118.42496)
		(end 254.765302 -118.194582)
		(width 0.14732)
		(layer "In2.Cu")
		(net "CLK_100M_DB2000_DN")
	)
	(segment
		(start 242.71732 -126.845568)
		(end 244.225064 -126.845568)
		(width 0.14732)
		(layer "In2.Cu")
		(net "CLK_100M_DB2000_DN")
	)
	(segment
		(start 250.450096 -121.736358)
		(end 250.656852 -121.756678)
		(width 0.14732)
		(layer "In2.Cu")
		(net "CLK_100M_DB2000_DN")
	)
	(segment
		(start 252.5395 -125.085602)
		(end 250.14936 -122.173492)
		(width 0.14732)
		(layer "In2.Cu")
		(net "CLK_100M_DB2000_DN")
	)
	(segment
		(start 256.356866 -122.350784)
		(end 256.81178 -121.97715)
		(width 0.14732)
		(layer "In2.Cu")
		(net "CLK_100M_DB2000_DN")
	)
	(segment
		(start 253.3269 -119.375174)
		(end 253.533656 -119.395494)
		(width 0.14732)
		(layer "In2.Cu")
		(net "CLK_100M_DB2000_DN")
	)
	(segment
		(start 255.923542 -117.244368)
		(end 256.203704 -117.01399)
		(width 0.14732)
		(layer "In2.Cu")
		(net "CLK_100M_DB2000_DN")
	)
	(segment
		(start 257.642106 -115.833398)
		(end 257.848862 -115.853718)
		(width 0.14732)
		(layer "In2.Cu")
		(net "CLK_100M_DB2000_DN")
	)
	(segment
		(start 257.361944 -116.063776)
		(end 257.642106 -115.833398)
		(width 0.14732)
		(layer "In2.Cu")
		(net "CLK_100M_DB2000_DN")
	)
	(segment
		(start 250.14936 -122.173492)
		(end 250.169934 -121.966736)
		(width 0.14732)
		(layer "In2.Cu")
		(net "CLK_100M_DB2000_DN")
	)
	(segment
		(start 262.99668 -98.085148)
		(end 262.684006 -97.772474)
		(width 0.14732)
		(layer "In2.Cu")
		(net "CLK_100M_DB2000_DN")
	)
	(segment
		(start 254.918464 -123.531376)
		(end 255.373378 -123.157742)
		(width 0.14732)
		(layer "In2.Cu")
		(net "CLK_100M_DB2000_DN")
	)
	(segment
		(start 255.923796 -122.307604)
		(end 256.356866 -122.350784)
		(width 0.14732)
		(layer "In2.Cu")
		(net "CLK_100M_DB2000_DN")
	)
	(segment
		(start 256.854706 -121.543826)
		(end 254.464566 -118.631716)
		(width 0.14732)
		(layer "In2.Cu")
		(net "CLK_100M_DB2000_DN")
	)
	(segment
		(start 258.796536 -114.9223)
		(end 261.253986 -112.905794)
		(width 0.14732)
		(layer "In2.Cu")
		(net "CLK_100M_DB2000_DN")
	)
	(segment
		(start 244.225064 -126.845568)
		(end 249.011694 -122.91695)
		(width 0.14732)
		(layer "In2.Cu")
		(net "CLK_100M_DB2000_DN")
	)
	(segment
		(start 262.684006 -97.772474)
		(end 262.40994 -97.772474)
		(width 0.14732)
		(layer "In2.Cu")
		(net "CLK_100M_DB2000_DN")
	)
	(segment
		(start 254.464566 -118.631716)
		(end 254.48514 -118.42496)
		(width 0.14732)
		(layer "In2.Cu")
		(net "CLK_100M_DB2000_DN")
	)
	(segment
		(start 253.026164 -119.812308)
		(end 253.046738 -119.605552)
		(width 0.14732)
		(layer "In2.Cu")
		(net "CLK_100M_DB2000_DN")
	)
	(segment
		(start 253.046992 -124.668788)
		(end 253.480062 -124.711968)
		(width 0.14732)
		(layer "In2.Cu")
		(net "CLK_100M_DB2000_DN")
	)
	(segment
		(start 253.533656 -119.395494)
		(end 255.923796 -122.307604)
		(width 0.14732)
		(layer "In2.Cu")
		(net "CLK_100M_DB2000_DN")
	)
	(segment
		(start 256.41046 -117.03431)
		(end 258.8006 -119.94642)
		(width 0.14732)
		(layer "In2.Cu")
		(net "CLK_100M_DB2000_DN")
	)
	(segment
		(start 259.73151 -119.182642)
		(end 257.34137 -116.270532)
		(width 0.14732)
		(layer "In2.Cu")
		(net "CLK_100M_DB2000_DN")
	)
	(segment
		(start 259.23367 -119.9896)
		(end 259.688584 -119.615966)
		(width 0.14732)
		(layer "In2.Cu")
		(net "CLK_100M_DB2000_DN")
	)
	(segment
		(start 242.42268 -127.140208)
		(end 242.71732 -126.845568)
		(width 0.14732)
		(layer "In2.Cu")
		(net "CLK_100M_DB2000_DN")
	)
	(segment
		(start 262.40994 -97.772474)
		(end 262.1153 -97.477834)
		(width 0.14732)
		(layer "In2.Cu")
		(net "CLK_100M_DB2000_DN")
	)
	(segment
		(start 258.779772 -115.08994)
		(end 258.796536 -114.9223)
		(width 0.14732)
		(layer "In2.Cu")
		(net "CLK_100M_DB2000_DN")
	)
	(segment
		(start 261.253986 -112.905794)
		(end 261.856474 -112.093248)
		(width 0.14732)
		(layer "In2.Cu")
		(net "CLK_100M_DB2000_DN")
	)
	(segment
		(start 261.126986 -118.435374)
		(end 261.169912 -118.00205)
		(width 0.14732)
		(layer "In2.Cu")
		(net "CLK_100M_DB2000_DN")
	)
	(segment
		(start 261.169912 -118.00205)
		(end 258.779772 -115.08994)
		(width 0.14732)
		(layer "In2.Cu")
		(net "CLK_100M_DB2000_DN")
	)
	(segment
		(start 259.688584 -119.615966)
		(end 259.73151 -119.182642)
		(width 0.14732)
		(layer "In2.Cu")
		(net "CLK_100M_DB2000_DN")
	)
	(segment
		(start 262.99668 -98.97999)
		(end 262.99668 -98.085148)
		(width 0.14732)
		(layer "In2.Cu")
		(net "CLK_100M_DB2000_DN")
	)
	(segment
		(start 258.250182 -120.796558)
		(end 258.293108 -120.363234)
		(width 0.14732)
		(layer "In2.Cu")
		(net "CLK_100M_DB2000_DN")
	)
	(segment
		(start 253.934976 -124.338334)
		(end 253.977902 -123.90501)
		(width 0.14732)
		(layer "In2.Cu")
		(net "CLK_100M_DB2000_DN")
	)
	(segment
		(start 258.8006 -119.94642)
		(end 259.23367 -119.9896)
		(width 0.14732)
		(layer "In2.Cu")
		(net "CLK_100M_DB2000_DN")
	)
	(segment
		(start 262.41248 -109.692948)
		(end 262.41248 -107.971082)
		(width 0.14732)
		(layer "In2.Cu")
		(net "CLK_100M_DB2000_DN")
	)
	(segment
		(start 254.765302 -118.194582)
		(end 254.972058 -118.214902)
		(width 0.14732)
		(layer "In2.Cu")
		(net "CLK_100M_DB2000_DN")
	)
	(segment
		(start 255.902968 -117.451124)
		(end 255.923542 -117.244368)
		(width 0.14732)
		(layer "In2.Cu")
		(net "CLK_100M_DB2000_DN")
	)
	(segment
		(start 257.34137 -116.270532)
		(end 257.361944 -116.063776)
		(width 0.14732)
		(layer "In2.Cu")
		(net "CLK_100M_DB2000_DN")
	)
	(segment
		(start 253.480062 -124.711968)
		(end 253.934976 -124.338334)
		(width 0.14732)
		(layer "In2.Cu")
		(net "CLK_100M_DB2000_DN")
	)
	(segment
		(start 249.011694 -122.91695)
		(end 249.21845 -122.93727)
		(width 0.14732)
		(layer "In2.Cu")
		(net "CLK_100M_DB2000_DN")
	)
	(segment
		(start 257.362198 -121.127012)
		(end 257.795268 -121.170192)
		(width 0.14732)
		(layer "In2.Cu")
		(net "CLK_100M_DB2000_DN")
	)
	(segment
		(start 250.169934 -121.966736)
		(end 250.450096 -121.736358)
		(width 0.14732)
		(layer "In2.Cu")
		(net "CLK_100M_DB2000_DN")
	)
	(segment
		(start 253.046738 -119.605552)
		(end 253.3269 -119.375174)
		(width 0.14732)
		(layer "In2.Cu")
		(net "CLK_100M_DB2000_DN")
	)
	(segment
		(start 256.203704 -117.01399)
		(end 256.41046 -117.03431)
		(width 0.14732)
		(layer "In2.Cu")
		(net "CLK_100M_DB2000_DN")
	)
	(segment
		(start 262.10768 -104.864916)
		(end 262.10768 -101.125782)
		(width 0.14732)
		(layer "In2.Cu")
		(net "CLK_100M_DB2000_DN")
	)
	(segment
		(start 255.373378 -123.157742)
		(end 255.416304 -122.724418)
		(width 0.14732)
		(layer "In2.Cu")
		(net "CLK_100M_DB2000_DN")
	)
	(segment
		(start 257.795268 -121.170192)
		(end 258.250182 -120.796558)
		(width 0.14732)
		(layer "In2.Cu")
		(net "CLK_100M_DB2000_DN")
	)
	(segment
		(start 254.972058 -118.214902)
		(end 257.362198 -121.127012)
		(width 0.14732)
		(layer "In2.Cu")
		(net "CLK_100M_DB2000_DN")
	)
	(segment
		(start 260.672072 -118.809008)
		(end 261.126986 -118.435374)
		(width 0.14732)
		(layer "In2.Cu")
		(net "CLK_100M_DB2000_DN")
	)
	(segment
		(start 250.656852 -121.756678)
		(end 253.046992 -124.668788)
		(width 0.14732)
		(layer "In2.Cu")
		(net "CLK_100M_DB2000_DN")
	)
	(segment
		(start 261.856474 -112.093248)
		(end 262.389366 -110.8075)
		(width 0.14732)
		(layer "In2.Cu")
		(net "CLK_100M_DB2000_DN")
	)
	(segment
		(start 262.41248 -107.971082)
		(end 262.10768 -104.864916)
		(width 0.14732)
		(layer "In2.Cu")
		(net "CLK_100M_DB2000_DN")
	)
	(segment
		(start 229.064566 -131.09702)
		(end 229.366826 -130.79476)
		(width 0.13208)
		(layer "F.Cu")
		(net "CLK_100M_DB2000_CPU1_BCLK3_DP")
	)
	(segment
		(start 232.130092 -128.89992)
		(end 232.247948 -129.017776)
		(width 0.13208)
		(layer "F.Cu")
		(net "CLK_100M_DB2000_CPU1_BCLK3_DP")
	)
	(segment
		(start 122.447812 -235.505752)
		(end 122.447812 -234.970066)
		(width 0.13208)
		(layer "F.Cu")
		(net "CLK_100M_DB2000_CPU1_BCLK3_DP")
	)
	(segment
		(start 122.448066 -235.506006)
		(end 122.447812 -235.505752)
		(width 0.13208)
		(layer "F.Cu")
		(net "CLK_100M_DB2000_CPU1_BCLK3_DP")
	)
	(segment
		(start 232.128822 -128.89992)
		(end 232.130092 -128.89992)
		(width 0.13208)
		(layer "F.Cu")
		(net "CLK_100M_DB2000_CPU1_BCLK3_DP")
	)
	(segment
		(start 231.701848 -128.89738)
		(end 232.126282 -128.89738)
		(width 0.13208)
		(layer "F.Cu")
		(net "CLK_100M_DB2000_CPU1_BCLK3_DP")
	)
	(segment
		(start 229.366826 -130.79476)
		(end 229.804468 -130.79476)
		(width 0.13208)
		(layer "F.Cu")
		(net "CLK_100M_DB2000_CPU1_BCLK3_DP")
	)
	(segment
		(start 232.126282 -128.89738)
		(end 232.128822 -128.89992)
		(width 0.13208)
		(layer "F.Cu")
		(net "CLK_100M_DB2000_CPU1_BCLK3_DP")
	)
	(segment
		(start 229.804468 -130.79476)
		(end 231.701848 -128.89738)
		(width 0.13208)
		(layer "F.Cu")
		(net "CLK_100M_DB2000_CPU1_BCLK3_DP")
	)
	(via
		(at 229.064566 -131.09702)
		(size 0.508)
		(drill 0.254)
		(layers "F.Cu" "B.Cu")
		(net "CLK_100M_DB2000_CPU1_BCLK3_DP")
	)
	(via
		(at 122.447812 -234.970066)
		(size 0.4572)
		(drill 0.2032)
		(layers "F.Cu" "B.Cu")
		(net "CLK_100M_DB2000_CPU1_BCLK3_DP")
	)
	(segment
		(start 159.45358 -200.703434)
		(end 159.45358 -221.258384)
		(width 0.13208)
		(layer "B.Cu")
		(net "CLK_100M_DB2000_CPU1_BCLK3_DP")
	)
	(segment
		(start 231.19334 -135.907018)
		(end 230.983282 -136.414002)
		(width 0.13208)
		(layer "B.Cu")
		(net "CLK_100M_DB2000_CPU1_BCLK3_DP")
	)
	(segment
		(start 228.332792 -130.787648)
		(end 227.98532 -131.13512)
		(width 0.13208)
		(layer "B.Cu")
		(net "CLK_100M_DB2000_CPU1_BCLK3_DP")
	)
	(segment
		(start 162.54984 -196.788532)
		(end 161.280094 -198.058532)
		(width 0.13208)
		(layer "B.Cu")
		(net "CLK_100M_DB2000_CPU1_BCLK3_DP")
	)
	(segment
		(start 170.83659 -170.042586)
		(end 162.54984 -190.048388)
		(width 0.13208)
		(layer "B.Cu")
		(net "CLK_100M_DB2000_CPU1_BCLK3_DP")
	)
	(segment
		(start 228.755194 -130.787648)
		(end 228.332792 -130.787648)
		(width 0.13208)
		(layer "B.Cu")
		(net "CLK_100M_DB2000_CPU1_BCLK3_DP")
	)
	(segment
		(start 125.080268 -234.645708)
		(end 125.069854 -234.651804)
		(width 0.0889)
		(layer "B.Cu")
		(net "CLK_100M_DB2000_CPU1_BCLK3_DP")
	)
	(segment
		(start 149.709124 -233.899964)
		(end 149.454108 -234.15498)
		(width 0.13208)
		(layer "B.Cu")
		(net "CLK_100M_DB2000_CPU1_BCLK3_DP")
	)
	(segment
		(start 230.227124 -133.715252)
		(end 230.844344 -134.4676)
		(width 0.13208)
		(layer "B.Cu")
		(net "CLK_100M_DB2000_CPU1_BCLK3_DP")
	)
	(segment
		(start 157.07868 -227.929948)
		(end 155.26258 -229.746048)
		(width 0.13208)
		(layer "B.Cu")
		(net "CLK_100M_DB2000_CPU1_BCLK3_DP")
	)
	(segment
		(start 147.787614 -235.821474)
		(end 139.404598 -235.821474)
		(width 0.13208)
		(layer "B.Cu")
		(net "CLK_100M_DB2000_CPU1_BCLK3_DP")
	)
	(segment
		(start 136.357614 -234.645708)
		(end 136.3472 -234.651804)
		(width 0.0889)
		(layer "B.Cu")
		(net "CLK_100M_DB2000_CPU1_BCLK3_DP")
	)
	(segment
		(start 128.839214 -234.645708)
		(end 128.824482 -234.654344)
		(width 0.0889)
		(layer "B.Cu")
		(net "CLK_100M_DB2000_CPU1_BCLK3_DP")
	)
	(segment
		(start 150.15464 -233.454448)
		(end 150.15464 -233.644694)
		(width 0.13208)
		(layer "B.Cu")
		(net "CLK_100M_DB2000_CPU1_BCLK3_DP")
	)
	(segment
		(start 229.752398 -137.644886)
		(end 229.164388 -137.888218)
		(width 0.13208)
		(layer "B.Cu")
		(net "CLK_100M_DB2000_CPU1_BCLK3_DP")
	)
	(segment
		(start 132.598414 -234.645708)
		(end 132.588 -234.651804)
		(width 0.0889)
		(layer "B.Cu")
		(net "CLK_100M_DB2000_CPU1_BCLK3_DP")
	)
	(segment
		(start 231.19334 -135.310372)
		(end 231.19334 -135.907018)
		(width 0.13208)
		(layer "B.Cu")
		(net "CLK_100M_DB2000_CPU1_BCLK3_DP")
	)
	(segment
		(start 139.3825 -235.821474)
		(end 139.347956 -235.78693)
		(width 0.0889)
		(layer "B.Cu")
		(net "CLK_100M_DB2000_CPU1_BCLK3_DP")
	)
	(segment
		(start 178.547014 -158.503366)
		(end 170.83659 -170.042586)
		(width 0.13208)
		(layer "B.Cu")
		(net "CLK_100M_DB2000_CPU1_BCLK3_DP")
	)
	(segment
		(start 149.008592 -234.600496)
		(end 147.787614 -235.821474)
		(width 0.13208)
		(layer "B.Cu")
		(net "CLK_100M_DB2000_CPU1_BCLK3_DP")
	)
	(segment
		(start 122.077734 -234.912662)
		(end 122.135138 -234.970066)
		(width 0.0889)
		(layer "B.Cu")
		(net "CLK_100M_DB2000_CPU1_BCLK3_DP")
	)
	(segment
		(start 131.658868 -234.645708)
		(end 131.648454 -234.651804)
		(width 0.0889)
		(layer "B.Cu")
		(net "CLK_100M_DB2000_CPU1_BCLK3_DP")
	)
	(segment
		(start 230.983282 -136.414002)
		(end 229.752398 -137.644886)
		(width 0.13208)
		(layer "B.Cu")
		(net "CLK_100M_DB2000_CPU1_BCLK3_DP")
	)
	(segment
		(start 133.538468 -234.645708)
		(end 133.528054 -234.651804)
		(width 0.0889)
		(layer "B.Cu")
		(net "CLK_100M_DB2000_CPU1_BCLK3_DP")
	)
	(segment
		(start 122.260614 -234.645708)
		(end 122.25909 -234.64647)
		(width 0.0889)
		(layer "B.Cu")
		(net "CLK_100M_DB2000_CPU1_BCLK3_DP")
	)
	(segment
		(start 130.718814 -234.645708)
		(end 130.704082 -234.654344)
		(width 0.0889)
		(layer "B.Cu")
		(net "CLK_100M_DB2000_CPU1_BCLK3_DP")
	)
	(segment
		(start 153.86304 -229.746048)
		(end 150.15464 -233.454448)
		(width 0.13208)
		(layer "B.Cu")
		(net "CLK_100M_DB2000_CPU1_BCLK3_DP")
	)
	(segment
		(start 227.98532 -131.13512)
		(end 227.98532 -131.726686)
		(width 0.13208)
		(layer "B.Cu")
		(net "CLK_100M_DB2000_CPU1_BCLK3_DP")
	)
	(segment
		(start 149.454108 -234.345226)
		(end 149.198838 -234.600496)
		(width 0.13208)
		(layer "B.Cu")
		(net "CLK_100M_DB2000_CPU1_BCLK3_DP")
	)
	(segment
		(start 228.80955 -132.76834)
		(end 230.227124 -133.715252)
		(width 0.13208)
		(layer "B.Cu")
		(net "CLK_100M_DB2000_CPU1_BCLK3_DP")
	)
	(segment
		(start 149.198838 -234.600496)
		(end 149.008592 -234.600496)
		(width 0.13208)
		(layer "B.Cu")
		(net "CLK_100M_DB2000_CPU1_BCLK3_DP")
	)
	(segment
		(start 230.844344 -134.4676)
		(end 231.19334 -135.310372)
		(width 0.13208)
		(layer "B.Cu")
		(net "CLK_100M_DB2000_CPU1_BCLK3_DP")
	)
	(segment
		(start 149.89937 -233.899964)
		(end 149.709124 -233.899964)
		(width 0.13208)
		(layer "B.Cu")
		(net "CLK_100M_DB2000_CPU1_BCLK3_DP")
	)
	(segment
		(start 159.45358 -221.258384)
		(end 157.07868 -223.633284)
		(width 0.13208)
		(layer "B.Cu")
		(net "CLK_100M_DB2000_CPU1_BCLK3_DP")
	)
	(segment
		(start 197.687692 -144.149064)
		(end 189.516766 -147.533868)
		(width 0.13208)
		(layer "B.Cu")
		(net "CLK_100M_DB2000_CPU1_BCLK3_DP")
	)
	(segment
		(start 189.516766 -147.533868)
		(end 178.547014 -158.503366)
		(width 0.13208)
		(layer "B.Cu")
		(net "CLK_100M_DB2000_CPU1_BCLK3_DP")
	)
	(segment
		(start 126.959614 -234.645708)
		(end 126.944882 -234.654344)
		(width 0.0889)
		(layer "B.Cu")
		(net "CLK_100M_DB2000_CPU1_BCLK3_DP")
	)
	(segment
		(start 139.347956 -235.78693)
		(end 138.551158 -235.78693)
		(width 0.0889)
		(layer "B.Cu")
		(net "CLK_100M_DB2000_CPU1_BCLK3_DP")
	)
	(segment
		(start 126.019814 -234.645708)
		(end 126.0094 -234.651804)
		(width 0.0889)
		(layer "B.Cu")
		(net "CLK_100M_DB2000_CPU1_BCLK3_DP")
	)
	(segment
		(start 139.404598 -235.821474)
		(end 139.3825 -235.821474)
		(width 0.0889)
		(layer "B.Cu")
		(net "CLK_100M_DB2000_CPU1_BCLK3_DP")
	)
	(segment
		(start 137.35939 -234.595162)
		(end 136.544812 -234.595162)
		(width 0.0889)
		(layer "B.Cu")
		(net "CLK_100M_DB2000_CPU1_BCLK3_DP")
	)
	(segment
		(start 138.551158 -235.78693)
		(end 137.35939 -234.595162)
		(width 0.0889)
		(layer "B.Cu")
		(net "CLK_100M_DB2000_CPU1_BCLK3_DP")
	)
	(segment
		(start 229.164388 -137.888218)
		(end 197.687692 -144.149064)
		(width 0.13208)
		(layer "B.Cu")
		(net "CLK_100M_DB2000_CPU1_BCLK3_DP")
	)
	(segment
		(start 155.26258 -229.746048)
		(end 153.86304 -229.746048)
		(width 0.13208)
		(layer "B.Cu")
		(net "CLK_100M_DB2000_CPU1_BCLK3_DP")
	)
	(segment
		(start 122.135138 -234.970066)
		(end 122.447812 -234.970066)
		(width 0.0889)
		(layer "B.Cu")
		(net "CLK_100M_DB2000_CPU1_BCLK3_DP")
	)
	(segment
		(start 157.07868 -223.633284)
		(end 157.07868 -227.929948)
		(width 0.13208)
		(layer "B.Cu")
		(net "CLK_100M_DB2000_CPU1_BCLK3_DP")
	)
	(segment
		(start 124.140214 -234.645708)
		(end 124.125482 -234.654344)
		(width 0.0889)
		(layer "B.Cu")
		(net "CLK_100M_DB2000_CPU1_BCLK3_DP")
	)
	(segment
		(start 161.280094 -198.058532)
		(end 160.701228 -199.455786)
		(width 0.13208)
		(layer "B.Cu")
		(net "CLK_100M_DB2000_CPU1_BCLK3_DP")
	)
	(segment
		(start 227.98532 -131.726686)
		(end 228.139244 -132.097526)
		(width 0.13208)
		(layer "B.Cu")
		(net "CLK_100M_DB2000_CPU1_BCLK3_DP")
	)
	(segment
		(start 229.064566 -131.09702)
		(end 228.755194 -130.787648)
		(width 0.13208)
		(layer "B.Cu")
		(net "CLK_100M_DB2000_CPU1_BCLK3_DP")
	)
	(segment
		(start 149.454108 -234.15498)
		(end 149.454108 -234.345226)
		(width 0.13208)
		(layer "B.Cu")
		(net "CLK_100M_DB2000_CPU1_BCLK3_DP")
	)
	(segment
		(start 162.54984 -190.048388)
		(end 162.54984 -196.788532)
		(width 0.13208)
		(layer "B.Cu")
		(net "CLK_100M_DB2000_CPU1_BCLK3_DP")
	)
	(segment
		(start 160.701228 -199.455786)
		(end 159.45358 -200.703434)
		(width 0.13208)
		(layer "B.Cu")
		(net "CLK_100M_DB2000_CPU1_BCLK3_DP")
	)
	(segment
		(start 127.899414 -234.645708)
		(end 127.884682 -234.654344)
		(width 0.0889)
		(layer "B.Cu")
		(net "CLK_100M_DB2000_CPU1_BCLK3_DP")
	)
	(segment
		(start 150.15464 -233.644694)
		(end 149.89937 -233.899964)
		(width 0.13208)
		(layer "B.Cu")
		(net "CLK_100M_DB2000_CPU1_BCLK3_DP")
	)
	(segment
		(start 228.139244 -132.097526)
		(end 228.80955 -132.76834)
		(width 0.13208)
		(layer "B.Cu")
		(net "CLK_100M_DB2000_CPU1_BCLK3_DP")
	)
	(arc
		(start 125.454664 -234.645708)
		(mid 125.267466 -234.595565)
		(end 125.080268 -234.645708)
		(width 0.0889)
		(layer "B.Cu")
		(net "CLK_100M_DB2000_CPU1_BCLK3_DP")
	)
	(arc
		(start 130.704082 -234.654344)
		(mid 130.427607 -234.721664)
		(end 130.15341 -234.645708)
		(width 0.0889)
		(layer "B.Cu")
		(net "CLK_100M_DB2000_CPU1_BCLK3_DP")
	)
	(arc
		(start 131.648454 -234.651804)
		(mid 131.370022 -234.72165)
		(end 131.09321 -234.645708)
		(width 0.0889)
		(layer "B.Cu")
		(net "CLK_100M_DB2000_CPU1_BCLK3_DP")
	)
	(arc
		(start 126.944882 -234.654344)
		(mid 126.668407 -234.721664)
		(end 126.39421 -234.645708)
		(width 0.0889)
		(layer "B.Cu")
		(net "CLK_100M_DB2000_CPU1_BCLK3_DP")
	)
	(arc
		(start 133.912864 -234.645708)
		(mid 133.725666 -234.595565)
		(end 133.538468 -234.645708)
		(width 0.0889)
		(layer "B.Cu")
		(net "CLK_100M_DB2000_CPU1_BCLK3_DP")
	)
	(arc
		(start 124.51461 -234.645708)
		(mid 124.327412 -234.595565)
		(end 124.140214 -234.645708)
		(width 0.0889)
		(layer "B.Cu")
		(net "CLK_100M_DB2000_CPU1_BCLK3_DP")
	)
	(arc
		(start 136.3472 -234.651804)
		(mid 136.069022 -234.721527)
		(end 135.792464 -234.645708)
		(width 0.0889)
		(layer "B.Cu")
		(net "CLK_100M_DB2000_CPU1_BCLK3_DP")
	)
	(arc
		(start 134.852664 -234.645708)
		(mid 134.665466 -234.595565)
		(end 134.478268 -234.645708)
		(width 0.0889)
		(layer "B.Cu")
		(net "CLK_100M_DB2000_CPU1_BCLK3_DP")
	)
	(arc
		(start 127.33401 -234.645708)
		(mid 127.146812 -234.595565)
		(end 126.959614 -234.645708)
		(width 0.0889)
		(layer "B.Cu")
		(net "CLK_100M_DB2000_CPU1_BCLK3_DP")
	)
	(arc
		(start 124.125482 -234.654344)
		(mid 123.849007 -234.721664)
		(end 123.57481 -234.645708)
		(width 0.0889)
		(layer "B.Cu")
		(net "CLK_100M_DB2000_CPU1_BCLK3_DP")
	)
	(arc
		(start 127.884682 -234.654344)
		(mid 127.608207 -234.721664)
		(end 127.33401 -234.645708)
		(width 0.0889)
		(layer "B.Cu")
		(net "CLK_100M_DB2000_CPU1_BCLK3_DP")
	)
	(arc
		(start 135.792464 -234.645708)
		(mid 135.605266 -234.595565)
		(end 135.418068 -234.645708)
		(width 0.0889)
		(layer "B.Cu")
		(net "CLK_100M_DB2000_CPU1_BCLK3_DP")
	)
	(arc
		(start 132.588 -234.651804)
		(mid 132.309822 -234.721527)
		(end 132.033264 -234.645708)
		(width 0.0889)
		(layer "B.Cu")
		(net "CLK_100M_DB2000_CPU1_BCLK3_DP")
	)
	(arc
		(start 130.15341 -234.645708)
		(mid 129.966212 -234.595565)
		(end 129.779014 -234.645708)
		(width 0.0889)
		(layer "B.Cu")
		(net "CLK_100M_DB2000_CPU1_BCLK3_DP")
	)
	(arc
		(start 134.478268 -234.645708)
		(mid 134.195566 -234.721484)
		(end 133.912864 -234.645708)
		(width 0.0889)
		(layer "B.Cu")
		(net "CLK_100M_DB2000_CPU1_BCLK3_DP")
	)
	(arc
		(start 122.63501 -234.645708)
		(mid 122.447812 -234.595565)
		(end 122.260614 -234.645708)
		(width 0.0889)
		(layer "B.Cu")
		(net "CLK_100M_DB2000_CPU1_BCLK3_DP")
	)
	(arc
		(start 126.39421 -234.645708)
		(mid 126.207012 -234.595565)
		(end 126.019814 -234.645708)
		(width 0.0889)
		(layer "B.Cu")
		(net "CLK_100M_DB2000_CPU1_BCLK3_DP")
	)
	(arc
		(start 132.033264 -234.645708)
		(mid 131.846066 -234.595565)
		(end 131.658868 -234.645708)
		(width 0.0889)
		(layer "B.Cu")
		(net "CLK_100M_DB2000_CPU1_BCLK3_DP")
	)
	(arc
		(start 123.200414 -234.645708)
		(mid 122.917712 -234.721484)
		(end 122.63501 -234.645708)
		(width 0.0889)
		(layer "B.Cu")
		(net "CLK_100M_DB2000_CPU1_BCLK3_DP")
	)
	(arc
		(start 128.824482 -234.654344)
		(mid 128.548007 -234.721664)
		(end 128.27381 -234.645708)
		(width 0.0889)
		(layer "B.Cu")
		(net "CLK_100M_DB2000_CPU1_BCLK3_DP")
	)
	(arc
		(start 125.069854 -234.651804)
		(mid 124.791422 -234.72165)
		(end 124.51461 -234.645708)
		(width 0.0889)
		(layer "B.Cu")
		(net "CLK_100M_DB2000_CPU1_BCLK3_DP")
	)
	(arc
		(start 129.779014 -234.645708)
		(mid 129.496312 -234.721484)
		(end 129.21361 -234.645708)
		(width 0.0889)
		(layer "B.Cu")
		(net "CLK_100M_DB2000_CPU1_BCLK3_DP")
	)
	(arc
		(start 132.97281 -234.645708)
		(mid 132.785612 -234.595565)
		(end 132.598414 -234.645708)
		(width 0.0889)
		(layer "B.Cu")
		(net "CLK_100M_DB2000_CPU1_BCLK3_DP")
	)
	(arc
		(start 131.09321 -234.645708)
		(mid 130.906012 -234.595565)
		(end 130.718814 -234.645708)
		(width 0.0889)
		(layer "B.Cu")
		(net "CLK_100M_DB2000_CPU1_BCLK3_DP")
	)
	(arc
		(start 133.528054 -234.651804)
		(mid 133.249622 -234.72165)
		(end 132.97281 -234.645708)
		(width 0.0889)
		(layer "B.Cu")
		(net "CLK_100M_DB2000_CPU1_BCLK3_DP")
	)
	(arc
		(start 122.25909 -234.64647)
		(mid 122.138363 -234.759091)
		(end 122.077734 -234.912662)
		(width 0.0889)
		(layer "B.Cu")
		(net "CLK_100M_DB2000_CPU1_BCLK3_DP")
	)
	(arc
		(start 136.544812 -234.595162)
		(mid 136.447889 -234.60812)
		(end 136.357614 -234.645708)
		(width 0.0889)
		(layer "B.Cu")
		(net "CLK_100M_DB2000_CPU1_BCLK3_DP")
	)
	(arc
		(start 126.0094 -234.651804)
		(mid 125.731222 -234.721527)
		(end 125.454664 -234.645708)
		(width 0.0889)
		(layer "B.Cu")
		(net "CLK_100M_DB2000_CPU1_BCLK3_DP")
	)
	(arc
		(start 123.57481 -234.645708)
		(mid 123.387612 -234.595565)
		(end 123.200414 -234.645708)
		(width 0.0889)
		(layer "B.Cu")
		(net "CLK_100M_DB2000_CPU1_BCLK3_DP")
	)
	(arc
		(start 128.27381 -234.645708)
		(mid 128.086612 -234.595565)
		(end 127.899414 -234.645708)
		(width 0.0889)
		(layer "B.Cu")
		(net "CLK_100M_DB2000_CPU1_BCLK3_DP")
	)
	(arc
		(start 129.21361 -234.645708)
		(mid 129.026412 -234.595565)
		(end 128.839214 -234.645708)
		(width 0.0889)
		(layer "B.Cu")
		(net "CLK_100M_DB2000_CPU1_BCLK3_DP")
	)
	(arc
		(start 135.418068 -234.645708)
		(mid 135.135366 -234.721484)
		(end 134.852664 -234.645708)
		(width 0.0889)
		(layer "B.Cu")
		(net "CLK_100M_DB2000_CPU1_BCLK3_DP")
	)
	(segment
		(start 229.366826 -130.53568)
		(end 229.697026 -130.53568)
		(width 0.13208)
		(layer "F.Cu")
		(net "CLK_100M_DB2000_CPU1_BCLK3_DN")
	)
	(segment
		(start 121.508012 -235.505752)
		(end 121.508012 -234.970066)
		(width 0.13208)
		(layer "F.Cu")
		(net "CLK_100M_DB2000_CPU1_BCLK3_DN")
	)
	(segment
		(start 229.697026 -130.53568)
		(end 231.594406 -128.6383)
		(width 0.13208)
		(layer "F.Cu")
		(net "CLK_100M_DB2000_CPU1_BCLK3_DN")
	)
	(segment
		(start 229.064566 -130.23342)
		(end 229.366826 -130.53568)
		(width 0.13208)
		(layer "F.Cu")
		(net "CLK_100M_DB2000_CPU1_BCLK3_DN")
	)
	(segment
		(start 121.508266 -235.506006)
		(end 121.508012 -235.505752)
		(width 0.13208)
		(layer "F.Cu")
		(net "CLK_100M_DB2000_CPU1_BCLK3_DN")
	)
	(segment
		(start 232.127552 -128.6383)
		(end 232.247948 -128.517904)
		(width 0.13208)
		(layer "F.Cu")
		(net "CLK_100M_DB2000_CPU1_BCLK3_DN")
	)
	(segment
		(start 231.594406 -128.6383)
		(end 232.127552 -128.6383)
		(width 0.13208)
		(layer "F.Cu")
		(net "CLK_100M_DB2000_CPU1_BCLK3_DN")
	)
	(via
		(at 121.508012 -234.970066)
		(size 0.4572)
		(drill 0.2032)
		(layers "F.Cu" "B.Cu")
		(net "CLK_100M_DB2000_CPU1_BCLK3_DN")
	)
	(via
		(at 229.064566 -130.23342)
		(size 0.508)
		(drill 0.254)
		(layers "F.Cu" "B.Cu")
		(net "CLK_100M_DB2000_CPU1_BCLK3_DN")
	)
	(segment
		(start 229.064566 -130.23342)
		(end 228.769418 -130.528568)
		(width 0.13208)
		(layer "B.Cu")
		(net "CLK_100M_DB2000_CPU1_BCLK3_DN")
	)
	(segment
		(start 125.939296 -234.471972)
		(end 125.924564 -234.480608)
		(width 0.0889)
		(layer "B.Cu")
		(net "CLK_100M_DB2000_CPU1_BCLK3_DN")
	)
	(segment
		(start 197.612 -143.89989)
		(end 189.369954 -147.314158)
		(width 0.13208)
		(layer "B.Cu")
		(net "CLK_100M_DB2000_CPU1_BCLK3_DN")
	)
	(segment
		(start 162.29076 -189.996826)
		(end 162.29076 -196.68109)
		(width 0.13208)
		(layer "B.Cu")
		(net "CLK_100M_DB2000_CPU1_BCLK3_DN")
	)
	(segment
		(start 128.754378 -234.474512)
		(end 128.743964 -234.480608)
		(width 0.0889)
		(layer "B.Cu")
		(net "CLK_100M_DB2000_CPU1_BCLK3_DN")
	)
	(segment
		(start 230.93426 -135.855456)
		(end 230.763572 -136.26719)
		(width 0.13208)
		(layer "B.Cu")
		(net "CLK_100M_DB2000_CPU1_BCLK3_DN")
	)
	(segment
		(start 230.051102 -133.909308)
		(end 230.619554 -134.60222)
		(width 0.13208)
		(layer "B.Cu")
		(net "CLK_100M_DB2000_CPU1_BCLK3_DN")
	)
	(segment
		(start 159.1945 -221.150942)
		(end 156.8196 -223.525842)
		(width 0.13208)
		(layer "B.Cu")
		(net "CLK_100M_DB2000_CPU1_BCLK3_DN")
	)
	(segment
		(start 139.3825 -235.562394)
		(end 139.34821 -235.596684)
		(width 0.0889)
		(layer "B.Cu")
		(net "CLK_100M_DB2000_CPU1_BCLK3_DN")
	)
	(segment
		(start 227.919534 -132.244338)
		(end 228.644196 -132.969762)
		(width 0.13208)
		(layer "B.Cu")
		(net "CLK_100M_DB2000_CPU1_BCLK3_DN")
	)
	(segment
		(start 124.059696 -234.471972)
		(end 124.044964 -234.480608)
		(width 0.0889)
		(layer "B.Cu")
		(net "CLK_100M_DB2000_CPU1_BCLK3_DN")
	)
	(segment
		(start 228.644196 -132.969762)
		(end 230.051102 -133.909308)
		(width 0.13208)
		(layer "B.Cu")
		(net "CLK_100M_DB2000_CPU1_BCLK3_DN")
	)
	(segment
		(start 139.34821 -235.596684)
		(end 138.630152 -235.596684)
		(width 0.0889)
		(layer "B.Cu")
		(net "CLK_100M_DB2000_CPU1_BCLK3_DN")
	)
	(segment
		(start 122.175778 -234.474512)
		(end 122.159268 -234.484164)
		(width 0.0889)
		(layer "B.Cu")
		(net "CLK_100M_DB2000_CPU1_BCLK3_DN")
	)
	(segment
		(start 156.8196 -223.525842)
		(end 156.8196 -227.822506)
		(width 0.13208)
		(layer "B.Cu")
		(net "CLK_100M_DB2000_CPU1_BCLK3_DN")
	)
	(segment
		(start 129.693924 -234.474512)
		(end 129.68351 -234.480608)
		(width 0.0889)
		(layer "B.Cu")
		(net "CLK_100M_DB2000_CPU1_BCLK3_DN")
	)
	(segment
		(start 229.08895 -137.639044)
		(end 197.612 -143.89989)
		(width 0.13208)
		(layer "B.Cu")
		(net "CLK_100M_DB2000_CPU1_BCLK3_DN")
	)
	(segment
		(start 121.886472 -234.90428)
		(end 121.820686 -234.970066)
		(width 0.0889)
		(layer "B.Cu")
		(net "CLK_100M_DB2000_CPU1_BCLK3_DN")
	)
	(segment
		(start 123.115324 -234.474512)
		(end 123.10491 -234.480608)
		(width 0.0889)
		(layer "B.Cu")
		(net "CLK_100M_DB2000_CPU1_BCLK3_DN")
	)
	(segment
		(start 228.22535 -130.528568)
		(end 227.72624 -131.027678)
		(width 0.13208)
		(layer "B.Cu")
		(net "CLK_100M_DB2000_CPU1_BCLK3_DN")
	)
	(segment
		(start 189.369954 -147.314158)
		(end 178.345592 -158.338012)
		(width 0.13208)
		(layer "B.Cu")
		(net "CLK_100M_DB2000_CPU1_BCLK3_DN")
	)
	(segment
		(start 160.481518 -199.308974)
		(end 159.1945 -200.595992)
		(width 0.13208)
		(layer "B.Cu")
		(net "CLK_100M_DB2000_CPU1_BCLK3_DN")
	)
	(segment
		(start 178.345592 -158.338012)
		(end 176.410366 -161.234628)
		(width 0.13208)
		(layer "B.Cu")
		(net "CLK_100M_DB2000_CPU1_BCLK3_DN")
	)
	(segment
		(start 162.29076 -196.68109)
		(end 161.060384 -197.91172)
		(width 0.13208)
		(layer "B.Cu")
		(net "CLK_100M_DB2000_CPU1_BCLK3_DN")
	)
	(segment
		(start 227.72624 -131.778502)
		(end 227.919534 -132.244338)
		(width 0.13208)
		(layer "B.Cu")
		(net "CLK_100M_DB2000_CPU1_BCLK3_DN")
	)
	(segment
		(start 130.638296 -234.471972)
		(end 130.623564 -234.480608)
		(width 0.0889)
		(layer "B.Cu")
		(net "CLK_100M_DB2000_CPU1_BCLK3_DN")
	)
	(segment
		(start 127.818896 -234.471972)
		(end 127.804164 -234.480608)
		(width 0.0889)
		(layer "B.Cu")
		(net "CLK_100M_DB2000_CPU1_BCLK3_DN")
	)
	(segment
		(start 156.8196 -227.822506)
		(end 155.155138 -229.486968)
		(width 0.13208)
		(layer "B.Cu")
		(net "CLK_100M_DB2000_CPU1_BCLK3_DN")
	)
	(segment
		(start 230.619554 -134.60222)
		(end 230.93426 -135.361934)
		(width 0.13208)
		(layer "B.Cu")
		(net "CLK_100M_DB2000_CPU1_BCLK3_DN")
	)
	(segment
		(start 170.60672 -169.91965)
		(end 162.29076 -189.996826)
		(width 0.13208)
		(layer "B.Cu")
		(net "CLK_100M_DB2000_CPU1_BCLK3_DN")
	)
	(segment
		(start 159.1945 -200.595992)
		(end 159.1945 -221.150942)
		(width 0.13208)
		(layer "B.Cu")
		(net "CLK_100M_DB2000_CPU1_BCLK3_DN")
	)
	(segment
		(start 153.755598 -229.486968)
		(end 147.680172 -235.562394)
		(width 0.13208)
		(layer "B.Cu")
		(net "CLK_100M_DB2000_CPU1_BCLK3_DN")
	)
	(segment
		(start 161.060384 -197.91172)
		(end 160.481518 -199.308974)
		(width 0.13208)
		(layer "B.Cu")
		(net "CLK_100M_DB2000_CPU1_BCLK3_DN")
	)
	(segment
		(start 176.410366 -161.234628)
		(end 170.60672 -169.91965)
		(width 0.13208)
		(layer "B.Cu")
		(net "CLK_100M_DB2000_CPU1_BCLK3_DN")
	)
	(segment
		(start 139.404598 -235.562394)
		(end 139.3825 -235.562394)
		(width 0.0889)
		(layer "B.Cu")
		(net "CLK_100M_DB2000_CPU1_BCLK3_DN")
	)
	(segment
		(start 147.680172 -235.562394)
		(end 139.404598 -235.562394)
		(width 0.13208)
		(layer "B.Cu")
		(net "CLK_100M_DB2000_CPU1_BCLK3_DN")
	)
	(segment
		(start 137.438384 -234.404916)
		(end 136.544558 -234.404916)
		(width 0.0889)
		(layer "B.Cu")
		(net "CLK_100M_DB2000_CPU1_BCLK3_DN")
	)
	(segment
		(start 228.769418 -130.528568)
		(end 228.22535 -130.528568)
		(width 0.13208)
		(layer "B.Cu")
		(net "CLK_100M_DB2000_CPU1_BCLK3_DN")
	)
	(segment
		(start 229.605586 -137.425176)
		(end 229.08895 -137.639044)
		(width 0.13208)
		(layer "B.Cu")
		(net "CLK_100M_DB2000_CPU1_BCLK3_DN")
	)
	(segment
		(start 227.72624 -131.027678)
		(end 227.72624 -131.778502)
		(width 0.13208)
		(layer "B.Cu")
		(net "CLK_100M_DB2000_CPU1_BCLK3_DN")
	)
	(segment
		(start 132.517896 -234.471972)
		(end 132.503164 -234.480608)
		(width 0.0889)
		(layer "B.Cu")
		(net "CLK_100M_DB2000_CPU1_BCLK3_DN")
	)
	(segment
		(start 138.630152 -235.596684)
		(end 137.438384 -234.404916)
		(width 0.0889)
		(layer "B.Cu")
		(net "CLK_100M_DB2000_CPU1_BCLK3_DN")
	)
	(segment
		(start 126.879096 -234.471972)
		(end 126.864364 -234.480608)
		(width 0.0889)
		(layer "B.Cu")
		(net "CLK_100M_DB2000_CPU1_BCLK3_DN")
	)
	(segment
		(start 230.93426 -135.361934)
		(end 230.93426 -135.855456)
		(width 0.13208)
		(layer "B.Cu")
		(net "CLK_100M_DB2000_CPU1_BCLK3_DN")
	)
	(segment
		(start 155.155138 -229.486968)
		(end 153.755598 -229.486968)
		(width 0.13208)
		(layer "B.Cu")
		(net "CLK_100M_DB2000_CPU1_BCLK3_DN")
	)
	(segment
		(start 121.820686 -234.970066)
		(end 121.508012 -234.970066)
		(width 0.0889)
		(layer "B.Cu")
		(net "CLK_100M_DB2000_CPU1_BCLK3_DN")
	)
	(segment
		(start 230.763572 -136.26719)
		(end 229.605586 -137.425176)
		(width 0.13208)
		(layer "B.Cu")
		(net "CLK_100M_DB2000_CPU1_BCLK3_DN")
	)
	(arc
		(start 126.864364 -234.480608)
		(mid 126.677166 -234.530751)
		(end 126.489968 -234.480608)
		(width 0.0889)
		(layer "B.Cu")
		(net "CLK_100M_DB2000_CPU1_BCLK3_DN")
	)
	(arc
		(start 127.429768 -234.480608)
		(mid 127.155569 -234.404773)
		(end 126.879096 -234.471972)
		(width 0.0889)
		(layer "B.Cu")
		(net "CLK_100M_DB2000_CPU1_BCLK3_DN")
	)
	(arc
		(start 136.262364 -234.480608)
		(mid 136.075166 -234.530751)
		(end 135.887968 -234.480608)
		(width 0.0889)
		(layer "B.Cu")
		(net "CLK_100M_DB2000_CPU1_BCLK3_DN")
	)
	(arc
		(start 122.730514 -234.480608)
		(mid 122.453955 -234.404865)
		(end 122.175778 -234.474512)
		(width 0.0889)
		(layer "B.Cu")
		(net "CLK_100M_DB2000_CPU1_BCLK3_DN")
	)
	(arc
		(start 134.382764 -234.480608)
		(mid 134.195566 -234.530751)
		(end 134.008368 -234.480608)
		(width 0.0889)
		(layer "B.Cu")
		(net "CLK_100M_DB2000_CPU1_BCLK3_DN")
	)
	(arc
		(start 134.008368 -234.480608)
		(mid 133.725666 -234.404832)
		(end 133.442964 -234.480608)
		(width 0.0889)
		(layer "B.Cu")
		(net "CLK_100M_DB2000_CPU1_BCLK3_DN")
	)
	(arc
		(start 129.68351 -234.480608)
		(mid 129.496312 -234.530751)
		(end 129.309114 -234.480608)
		(width 0.0889)
		(layer "B.Cu")
		(net "CLK_100M_DB2000_CPU1_BCLK3_DN")
	)
	(arc
		(start 136.41959 -234.418886)
		(mid 136.338653 -234.44383)
		(end 136.262364 -234.480608)
		(width 0.0889)
		(layer "B.Cu")
		(net "CLK_100M_DB2000_CPU1_BCLK3_DN")
	)
	(arc
		(start 136.544558 -234.404916)
		(mid 136.481686 -234.408424)
		(end 136.41959 -234.418886)
		(width 0.0889)
		(layer "B.Cu")
		(net "CLK_100M_DB2000_CPU1_BCLK3_DN")
	)
	(arc
		(start 123.670568 -234.480608)
		(mid 123.393755 -234.404738)
		(end 123.115324 -234.474512)
		(width 0.0889)
		(layer "B.Cu")
		(net "CLK_100M_DB2000_CPU1_BCLK3_DN")
	)
	(arc
		(start 131.188968 -234.480608)
		(mid 130.914769 -234.404773)
		(end 130.638296 -234.471972)
		(width 0.0889)
		(layer "B.Cu")
		(net "CLK_100M_DB2000_CPU1_BCLK3_DN")
	)
	(arc
		(start 128.369568 -234.480608)
		(mid 128.095369 -234.404773)
		(end 127.818896 -234.471972)
		(width 0.0889)
		(layer "B.Cu")
		(net "CLK_100M_DB2000_CPU1_BCLK3_DN")
	)
	(arc
		(start 124.044964 -234.480608)
		(mid 123.857766 -234.530751)
		(end 123.670568 -234.480608)
		(width 0.0889)
		(layer "B.Cu")
		(net "CLK_100M_DB2000_CPU1_BCLK3_DN")
	)
	(arc
		(start 129.309114 -234.480608)
		(mid 129.032555 -234.404865)
		(end 128.754378 -234.474512)
		(width 0.0889)
		(layer "B.Cu")
		(net "CLK_100M_DB2000_CPU1_BCLK3_DN")
	)
	(arc
		(start 122.159268 -234.484164)
		(mid 121.979616 -234.6536)
		(end 121.889266 -234.883452)
		(width 0.0889)
		(layer "B.Cu")
		(net "CLK_100M_DB2000_CPU1_BCLK3_DN")
	)
	(arc
		(start 123.10491 -234.480608)
		(mid 122.917712 -234.530751)
		(end 122.730514 -234.480608)
		(width 0.0889)
		(layer "B.Cu")
		(net "CLK_100M_DB2000_CPU1_BCLK3_DN")
	)
	(arc
		(start 133.442964 -234.480608)
		(mid 133.255766 -234.530751)
		(end 133.068568 -234.480608)
		(width 0.0889)
		(layer "B.Cu")
		(net "CLK_100M_DB2000_CPU1_BCLK3_DN")
	)
	(arc
		(start 125.550168 -234.480608)
		(mid 125.267466 -234.404832)
		(end 124.984764 -234.480608)
		(width 0.0889)
		(layer "B.Cu")
		(net "CLK_100M_DB2000_CPU1_BCLK3_DN")
	)
	(arc
		(start 135.322564 -234.480608)
		(mid 135.135366 -234.530751)
		(end 134.948168 -234.480608)
		(width 0.0889)
		(layer "B.Cu")
		(net "CLK_100M_DB2000_CPU1_BCLK3_DN")
	)
	(arc
		(start 134.948168 -234.480608)
		(mid 134.665466 -234.404832)
		(end 134.382764 -234.480608)
		(width 0.0889)
		(layer "B.Cu")
		(net "CLK_100M_DB2000_CPU1_BCLK3_DN")
	)
	(arc
		(start 133.068568 -234.480608)
		(mid 132.794369 -234.404773)
		(end 132.517896 -234.471972)
		(width 0.0889)
		(layer "B.Cu")
		(net "CLK_100M_DB2000_CPU1_BCLK3_DN")
	)
	(arc
		(start 132.503164 -234.480608)
		(mid 132.315966 -234.530751)
		(end 132.128768 -234.480608)
		(width 0.0889)
		(layer "B.Cu")
		(net "CLK_100M_DB2000_CPU1_BCLK3_DN")
	)
	(arc
		(start 135.887968 -234.480608)
		(mid 135.605266 -234.404832)
		(end 135.322564 -234.480608)
		(width 0.0889)
		(layer "B.Cu")
		(net "CLK_100M_DB2000_CPU1_BCLK3_DN")
	)
	(arc
		(start 127.804164 -234.480608)
		(mid 127.616966 -234.530751)
		(end 127.429768 -234.480608)
		(width 0.0889)
		(layer "B.Cu")
		(net "CLK_100M_DB2000_CPU1_BCLK3_DN")
	)
	(arc
		(start 126.489968 -234.480608)
		(mid 126.215769 -234.404773)
		(end 125.939296 -234.471972)
		(width 0.0889)
		(layer "B.Cu")
		(net "CLK_100M_DB2000_CPU1_BCLK3_DN")
	)
	(arc
		(start 124.610368 -234.480608)
		(mid 124.336169 -234.404773)
		(end 124.059696 -234.471972)
		(width 0.0889)
		(layer "B.Cu")
		(net "CLK_100M_DB2000_CPU1_BCLK3_DN")
	)
	(arc
		(start 132.128768 -234.480608)
		(mid 131.846066 -234.404832)
		(end 131.563364 -234.480608)
		(width 0.0889)
		(layer "B.Cu")
		(net "CLK_100M_DB2000_CPU1_BCLK3_DN")
	)
	(arc
		(start 131.563364 -234.480608)
		(mid 131.376166 -234.530751)
		(end 131.188968 -234.480608)
		(width 0.0889)
		(layer "B.Cu")
		(net "CLK_100M_DB2000_CPU1_BCLK3_DN")
	)
	(arc
		(start 130.249168 -234.480608)
		(mid 129.972355 -234.404738)
		(end 129.693924 -234.474512)
		(width 0.0889)
		(layer "B.Cu")
		(net "CLK_100M_DB2000_CPU1_BCLK3_DN")
	)
	(arc
		(start 121.889266 -234.883452)
		(mid 121.887771 -234.893853)
		(end 121.886472 -234.90428)
		(width 0.0889)
		(layer "B.Cu")
		(net "CLK_100M_DB2000_CPU1_BCLK3_DN")
	)
	(arc
		(start 128.743964 -234.480608)
		(mid 128.556766 -234.530751)
		(end 128.369568 -234.480608)
		(width 0.0889)
		(layer "B.Cu")
		(net "CLK_100M_DB2000_CPU1_BCLK3_DN")
	)
	(arc
		(start 124.984764 -234.480608)
		(mid 124.797566 -234.530751)
		(end 124.610368 -234.480608)
		(width 0.0889)
		(layer "B.Cu")
		(net "CLK_100M_DB2000_CPU1_BCLK3_DN")
	)
	(arc
		(start 130.623564 -234.480608)
		(mid 130.436366 -234.530751)
		(end 130.249168 -234.480608)
		(width 0.0889)
		(layer "B.Cu")
		(net "CLK_100M_DB2000_CPU1_BCLK3_DN")
	)
	(arc
		(start 125.924564 -234.480608)
		(mid 125.737366 -234.530751)
		(end 125.550168 -234.480608)
		(width 0.0889)
		(layer "B.Cu")
		(net "CLK_100M_DB2000_CPU1_BCLK3_DN")
	)
	(segment
		(start 226.44862 -135.283448)
		(end 226.14636 -134.981188)
		(width 0.13208)
		(layer "F.Cu")
		(net "CLK_100M_DB2000_CPU1_BCLK2_DP")
	)
	(segment
		(start 230.87965 -131.661154)
		(end 232.627678 -129.913126)
		(width 0.13208)
		(layer "F.Cu")
		(net "CLK_100M_DB2000_CPU1_BCLK2_DP")
	)
	(segment
		(start 228.812852 -132.517388)
		(end 230.87965 -131.661154)
		(width 0.13208)
		(layer "F.Cu")
		(net "CLK_100M_DB2000_CPU1_BCLK2_DP")
	)
	(segment
		(start 226.14636 -133.774688)
		(end 227.40366 -132.517388)
		(width 0.13208)
		(layer "F.Cu")
		(net "CLK_100M_DB2000_CPU1_BCLK2_DP")
	)
	(segment
		(start 102.242112 -236.319822)
		(end 102.242366 -236.319568)
		(width 0.13208)
		(layer "F.Cu")
		(net "CLK_100M_DB2000_CPU1_BCLK2_DP")
	)
	(segment
		(start 102.242366 -236.319568)
		(end 102.242366 -235.783882)
		(width 0.13208)
		(layer "F.Cu")
		(net "CLK_100M_DB2000_CPU1_BCLK2_DP")
	)
	(segment
		(start 232.630218 -129.635758)
		(end 232.748074 -129.517902)
		(width 0.13208)
		(layer "F.Cu")
		(net "CLK_100M_DB2000_CPU1_BCLK2_DP")
	)
	(segment
		(start 227.40366 -132.517388)
		(end 228.812852 -132.517388)
		(width 0.13208)
		(layer "F.Cu")
		(net "CLK_100M_DB2000_CPU1_BCLK2_DP")
	)
	(segment
		(start 232.630218 -129.637282)
		(end 232.630218 -129.635758)
		(width 0.13208)
		(layer "F.Cu")
		(net "CLK_100M_DB2000_CPU1_BCLK2_DP")
	)
	(segment
		(start 226.14636 -134.981188)
		(end 226.14636 -133.774688)
		(width 0.13208)
		(layer "F.Cu")
		(net "CLK_100M_DB2000_CPU1_BCLK2_DP")
	)
	(segment
		(start 232.627678 -129.639822)
		(end 232.630218 -129.637282)
		(width 0.13208)
		(layer "F.Cu")
		(net "CLK_100M_DB2000_CPU1_BCLK2_DP")
	)
	(segment
		(start 232.627678 -129.913126)
		(end 232.627678 -129.639822)
		(width 0.13208)
		(layer "F.Cu")
		(net "CLK_100M_DB2000_CPU1_BCLK2_DP")
	)
	(via
		(at 226.44862 -135.283448)
		(size 0.508)
		(drill 0.254)
		(layers "F.Cu" "B.Cu")
		(net "CLK_100M_DB2000_CPU1_BCLK2_DP")
	)
	(via
		(at 102.242366 -235.783882)
		(size 0.4572)
		(drill 0.2032)
		(layers "F.Cu" "B.Cu")
		(net "CLK_100M_DB2000_CPU1_BCLK2_DP")
	)
	(segment
		(start 108.624878 -143.320008)
		(end 107.25531 -143.887444)
		(width 0.13208)
		(layer "B.Cu")
		(net "CLK_100M_DB2000_CPU1_BCLK2_DP")
	)
	(segment
		(start 101.996748 -236.078776)
		(end 102.085902 -236.0549)
		(width 0.0889)
		(layer "B.Cu")
		(net "CLK_100M_DB2000_CPU1_BCLK2_DP")
	)
	(segment
		(start 66.633598 -189.973966)
		(end 66.772282 -190.310262)
		(width 0.13208)
		(layer "B.Cu")
		(net "CLK_100M_DB2000_CPU1_BCLK2_DP")
	)
	(segment
		(start 68.01612 -192.328546)
		(end 68.01612 -199.07504)
		(width 0.13208)
		(layer "B.Cu")
		(net "CLK_100M_DB2000_CPU1_BCLK2_DP")
	)
	(segment
		(start 63.279274 -219.835476)
		(end 63.279274 -232.082086)
		(width 0.13208)
		(layer "B.Cu")
		(net "CLK_100M_DB2000_CPU1_BCLK2_DP")
	)
	(segment
		(start 63.535814 -232.700322)
		(end 65.82918 -234.232958)
		(width 0.13208)
		(layer "B.Cu")
		(net "CLK_100M_DB2000_CPU1_BCLK2_DP")
	)
	(segment
		(start 87.110316 -236.597952)
		(end 87.110316 -236.57941)
		(width 0.0889)
		(layer "B.Cu")
		(net "CLK_100M_DB2000_CPU1_BCLK2_DP")
	)
	(segment
		(start 63.10376 -219.659962)
		(end 63.279274 -219.835476)
		(width 0.13208)
		(layer "B.Cu")
		(net "CLK_100M_DB2000_CPU1_BCLK2_DP")
	)
	(segment
		(start 107.25531 -143.887444)
		(end 77.47 -173.672754)
		(width 0.13208)
		(layer "B.Cu")
		(net "CLK_100M_DB2000_CPU1_BCLK2_DP")
	)
	(segment
		(start 226.108514 -136.466326)
		(end 225.155506 -137.419588)
		(width 0.13208)
		(layer "B.Cu")
		(net "CLK_100M_DB2000_CPU1_BCLK2_DP")
	)
	(segment
		(start 83.56092 -238.080296)
		(end 83.59648 -238.115856)
		(width 0.0889)
		(layer "B.Cu")
		(net "CLK_100M_DB2000_CPU1_BCLK2_DP")
	)
	(segment
		(start 64.016128 -203.27239)
		(end 63.374016 -203.538836)
		(width 0.13208)
		(layer "B.Cu")
		(net "CLK_100M_DB2000_CPU1_BCLK2_DP")
	)
	(segment
		(start 67.845178 -191.914272)
		(end 68.01612 -192.328546)
		(width 0.13208)
		(layer "B.Cu")
		(net "CLK_100M_DB2000_CPU1_BCLK2_DP")
	)
	(segment
		(start 95.850964 -236.10824)
		(end 95.865696 -236.099604)
		(width 0.0889)
		(layer "B.Cu")
		(net "CLK_100M_DB2000_CPU1_BCLK2_DP")
	)
	(segment
		(start 223.249236 -137.798556)
		(end 186.027822 -143.320008)
		(width 0.13208)
		(layer "B.Cu")
		(net "CLK_100M_DB2000_CPU1_BCLK2_DP")
	)
	(segment
		(start 65.94348 -182.891938)
		(end 65.94348 -186.505342)
		(width 0.13208)
		(layer "B.Cu")
		(net "CLK_100M_DB2000_CPU1_BCLK2_DP")
	)
	(segment
		(start 225.155506 -137.419588)
		(end 223.249236 -137.798556)
		(width 0.13208)
		(layer "B.Cu")
		(net "CLK_100M_DB2000_CPU1_BCLK2_DP")
	)
	(segment
		(start 89.272364 -236.10824)
		(end 89.287096 -236.099604)
		(width 0.0889)
		(layer "B.Cu")
		(net "CLK_100M_DB2000_CPU1_BCLK2_DP")
	)
	(segment
		(start 74.014838 -237.030006)
		(end 74.088498 -237.186216)
		(width 0.13208)
		(layer "B.Cu")
		(net "CLK_100M_DB2000_CPU1_BCLK2_DP")
	)
	(segment
		(start 63.10376 -203.889102)
		(end 63.10376 -219.659962)
		(width 0.13208)
		(layer "B.Cu")
		(net "CLK_100M_DB2000_CPU1_BCLK2_DP")
	)
	(segment
		(start 86.916768 -236.925866)
		(end 86.922864 -236.92231)
		(width 0.0889)
		(layer "B.Cu")
		(net "CLK_100M_DB2000_CPU1_BCLK2_DP")
	)
	(segment
		(start 83.59648 -238.115856)
		(end 86.243922 -238.115856)
		(width 0.0889)
		(layer "B.Cu")
		(net "CLK_100M_DB2000_CPU1_BCLK2_DP")
	)
	(segment
		(start 63.279274 -232.082086)
		(end 63.535814 -232.700322)
		(width 0.13208)
		(layer "B.Cu")
		(net "CLK_100M_DB2000_CPU1_BCLK2_DP")
	)
	(segment
		(start 94.911164 -236.10824)
		(end 94.925896 -236.099604)
		(width 0.0889)
		(layer "B.Cu")
		(net "CLK_100M_DB2000_CPU1_BCLK2_DP")
	)
	(segment
		(start 72.890634 -178.23434)
		(end 72.49541 -179.535328)
		(width 0.13208)
		(layer "B.Cu")
		(net "CLK_100M_DB2000_CPU1_BCLK2_DP")
	)
	(segment
		(start 74.673714 -177.07483)
		(end 73.279762 -177.651918)
		(width 0.13208)
		(layer "B.Cu")
		(net "CLK_100M_DB2000_CPU1_BCLK2_DP")
	)
	(segment
		(start 77.47 -175.617124)
		(end 76.012294 -177.07483)
		(width 0.13208)
		(layer "B.Cu")
		(net "CLK_100M_DB2000_CPU1_BCLK2_DP")
	)
	(segment
		(start 186.027822 -143.320008)
		(end 108.624878 -143.320008)
		(width 0.13208)
		(layer "B.Cu")
		(net "CLK_100M_DB2000_CPU1_BCLK2_DP")
	)
	(segment
		(start 74.603102 -237.240572)
		(end 74.962258 -237.368842)
		(width 0.13208)
		(layer "B.Cu")
		(net "CLK_100M_DB2000_CPU1_BCLK2_DP")
	)
	(segment
		(start 86.243922 -238.115856)
		(end 86.640162 -237.719616)
		(width 0.0889)
		(layer "B.Cu")
		(net "CLK_100M_DB2000_CPU1_BCLK2_DP")
	)
	(segment
		(start 72.49541 -179.535328)
		(end 70.93585 -181.094888)
		(width 0.13208)
		(layer "B.Cu")
		(net "CLK_100M_DB2000_CPU1_BCLK2_DP")
	)
	(segment
		(start 70.93585 -181.094888)
		(end 67.74053 -181.094888)
		(width 0.13208)
		(layer "B.Cu")
		(net "CLK_100M_DB2000_CPU1_BCLK2_DP")
	)
	(segment
		(start 226.14636 -135.585708)
		(end 226.14636 -136.42848)
		(width 0.13208)
		(layer "B.Cu")
		(net "CLK_100M_DB2000_CPU1_BCLK2_DP")
	)
	(segment
		(start 86.640162 -237.719616)
		(end 86.640162 -237.411768)
		(width 0.0889)
		(layer "B.Cu")
		(net "CLK_100M_DB2000_CPU1_BCLK2_DP")
	)
	(segment
		(start 102.085902 -236.0549)
		(end 102.242366 -235.783882)
		(width 0.0889)
		(layer "B.Cu")
		(net "CLK_100M_DB2000_CPU1_BCLK2_DP")
	)
	(segment
		(start 83.538822 -238.082836)
		(end 83.541362 -238.080296)
		(width 0.0889)
		(layer "B.Cu")
		(net "CLK_100M_DB2000_CPU1_BCLK2_DP")
	)
	(segment
		(start 74.962258 -237.368842)
		(end 75.035918 -237.524798)
		(width 0.13208)
		(layer "B.Cu")
		(net "CLK_100M_DB2000_CPU1_BCLK2_DP")
	)
	(segment
		(start 93.031564 -236.10824)
		(end 93.046296 -236.099604)
		(width 0.0889)
		(layer "B.Cu")
		(net "CLK_100M_DB2000_CPU1_BCLK2_DP")
	)
	(segment
		(start 101.489764 -236.10824)
		(end 101.504496 -236.099604)
		(width 0.0889)
		(layer "B.Cu")
		(net "CLK_100M_DB2000_CPU1_BCLK2_DP")
	)
	(segment
		(start 90.212164 -236.10824)
		(end 90.222578 -236.102144)
		(width 0.0889)
		(layer "B.Cu")
		(net "CLK_100M_DB2000_CPU1_BCLK2_DP")
	)
	(segment
		(start 98.670364 -236.10824)
		(end 98.678238 -236.103668)
		(width 0.0889)
		(layer "B.Cu")
		(net "CLK_100M_DB2000_CPU1_BCLK2_DP")
	)
	(segment
		(start 73.49998 -236.975396)
		(end 73.655682 -236.901736)
		(width 0.13208)
		(layer "B.Cu")
		(net "CLK_100M_DB2000_CPU1_BCLK2_DP")
	)
	(segment
		(start 76.017628 -237.875826)
		(end 77.058266 -238.082836)
		(width 0.13208)
		(layer "B.Cu")
		(net "CLK_100M_DB2000_CPU1_BCLK2_DP")
	)
	(segment
		(start 92.091764 -236.10824)
		(end 92.106496 -236.099604)
		(width 0.0889)
		(layer "B.Cu")
		(net "CLK_100M_DB2000_CPU1_BCLK2_DP")
	)
	(segment
		(start 66.772282 -190.310262)
		(end 67.845178 -191.914272)
		(width 0.13208)
		(layer "B.Cu")
		(net "CLK_100M_DB2000_CPU1_BCLK2_DP")
	)
	(segment
		(start 91.15171 -236.10824)
		(end 91.162124 -236.102144)
		(width 0.0889)
		(layer "B.Cu")
		(net "CLK_100M_DB2000_CPU1_BCLK2_DP")
	)
	(segment
		(start 76.012294 -177.07483)
		(end 74.673714 -177.07483)
		(width 0.13208)
		(layer "B.Cu")
		(net "CLK_100M_DB2000_CPU1_BCLK2_DP")
	)
	(segment
		(start 63.160656 -203.751688)
		(end 63.10376 -203.889102)
		(width 0.13208)
		(layer "B.Cu")
		(net "CLK_100M_DB2000_CPU1_BCLK2_DP")
	)
	(segment
		(start 73.279762 -177.651918)
		(end 72.890634 -178.23434)
		(width 0.13208)
		(layer "B.Cu")
		(net "CLK_100M_DB2000_CPU1_BCLK2_DP")
	)
	(segment
		(start 63.374016 -203.538836)
		(end 63.160656 -203.751688)
		(width 0.13208)
		(layer "B.Cu")
		(net "CLK_100M_DB2000_CPU1_BCLK2_DP")
	)
	(segment
		(start 226.14636 -136.42848)
		(end 226.108514 -136.466326)
		(width 0.13208)
		(layer "B.Cu")
		(net "CLK_100M_DB2000_CPU1_BCLK2_DP")
	)
	(segment
		(start 86.924388 -236.921548)
		(end 86.931754 -236.91723)
		(width 0.0889)
		(layer "B.Cu")
		(net "CLK_100M_DB2000_CPU1_BCLK2_DP")
	)
	(segment
		(start 66.048636 -201.914252)
		(end 64.016128 -203.27239)
		(width 0.13208)
		(layer "B.Cu")
		(net "CLK_100M_DB2000_CPU1_BCLK2_DP")
	)
	(segment
		(start 74.088498 -237.186216)
		(end 74.447146 -237.314232)
		(width 0.13208)
		(layer "B.Cu")
		(net "CLK_100M_DB2000_CPU1_BCLK2_DP")
	)
	(segment
		(start 75.035918 -237.524798)
		(end 76.017628 -237.875826)
		(width 0.13208)
		(layer "B.Cu")
		(net "CLK_100M_DB2000_CPU1_BCLK2_DP")
	)
	(segment
		(start 77.058266 -238.082836)
		(end 83.538822 -238.082836)
		(width 0.13208)
		(layer "B.Cu")
		(net "CLK_100M_DB2000_CPU1_BCLK2_DP")
	)
	(segment
		(start 98.678238 -236.103668)
		(end 98.685096 -236.099604)
		(width 0.0889)
		(layer "B.Cu")
		(net "CLK_100M_DB2000_CPU1_BCLK2_DP")
	)
	(segment
		(start 67.74053 -181.094888)
		(end 65.94348 -182.891938)
		(width 0.13208)
		(layer "B.Cu")
		(net "CLK_100M_DB2000_CPU1_BCLK2_DP")
	)
	(segment
		(start 99.610164 -236.10824)
		(end 99.624896 -236.099604)
		(width 0.0889)
		(layer "B.Cu")
		(net "CLK_100M_DB2000_CPU1_BCLK2_DP")
	)
	(segment
		(start 97.73031 -236.10824)
		(end 97.740724 -236.102144)
		(width 0.0889)
		(layer "B.Cu")
		(net "CLK_100M_DB2000_CPU1_BCLK2_DP")
	)
	(segment
		(start 226.44862 -135.283448)
		(end 226.14636 -135.585708)
		(width 0.13208)
		(layer "B.Cu")
		(net "CLK_100M_DB2000_CPU1_BCLK2_DP")
	)
	(segment
		(start 83.541362 -238.080296)
		(end 83.56092 -238.080296)
		(width 0.0889)
		(layer "B.Cu")
		(net "CLK_100M_DB2000_CPU1_BCLK2_DP")
	)
	(segment
		(start 67.399916 -200.56348)
		(end 66.048636 -201.914252)
		(width 0.13208)
		(layer "B.Cu")
		(net "CLK_100M_DB2000_CPU1_BCLK2_DP")
	)
	(segment
		(start 86.922864 -236.92231)
		(end 86.924388 -236.921548)
		(width 0.0889)
		(layer "B.Cu")
		(net "CLK_100M_DB2000_CPU1_BCLK2_DP")
	)
	(segment
		(start 68.01612 -199.07504)
		(end 67.399916 -200.56348)
		(width 0.13208)
		(layer "B.Cu")
		(net "CLK_100M_DB2000_CPU1_BCLK2_DP")
	)
	(segment
		(start 65.94348 -186.505342)
		(end 66.633598 -189.973966)
		(width 0.13208)
		(layer "B.Cu")
		(net "CLK_100M_DB2000_CPU1_BCLK2_DP")
	)
	(segment
		(start 74.447146 -237.314232)
		(end 74.603102 -237.240572)
		(width 0.13208)
		(layer "B.Cu")
		(net "CLK_100M_DB2000_CPU1_BCLK2_DP")
	)
	(segment
		(start 65.82918 -234.232958)
		(end 73.49998 -236.975396)
		(width 0.13208)
		(layer "B.Cu")
		(net "CLK_100M_DB2000_CPU1_BCLK2_DP")
	)
	(segment
		(start 77.47 -173.672754)
		(end 77.47 -175.617124)
		(width 0.13208)
		(layer "B.Cu")
		(net "CLK_100M_DB2000_CPU1_BCLK2_DP")
	)
	(segment
		(start 96.790764 -236.10824)
		(end 96.801178 -236.102144)
		(width 0.0889)
		(layer "B.Cu")
		(net "CLK_100M_DB2000_CPU1_BCLK2_DP")
	)
	(segment
		(start 73.655682 -236.901736)
		(end 74.014838 -237.030006)
		(width 0.13208)
		(layer "B.Cu")
		(net "CLK_100M_DB2000_CPU1_BCLK2_DP")
	)
	(arc
		(start 101.976682 -236.070648)
		(mid 101.986754 -236.074615)
		(end 101.996748 -236.078776)
		(width 0.0889)
		(layer "B.Cu")
		(net "CLK_100M_DB2000_CPU1_BCLK2_DP")
	)
	(arc
		(start 92.657168 -236.10824)
		(mid 92.844366 -236.158383)
		(end 93.031564 -236.10824)
		(width 0.0889)
		(layer "B.Cu")
		(net "CLK_100M_DB2000_CPU1_BCLK2_DP")
	)
	(arc
		(start 86.640162 -237.411768)
		(mid 86.714153 -237.132202)
		(end 86.916768 -236.925866)
		(width 0.0889)
		(layer "B.Cu")
		(net "CLK_100M_DB2000_CPU1_BCLK2_DP")
	)
	(arc
		(start 87.110316 -236.57941)
		(mid 87.190478 -236.307221)
		(end 87.392764 -236.10824)
		(width 0.0889)
		(layer "B.Cu")
		(net "CLK_100M_DB2000_CPU1_BCLK2_DP")
	)
	(arc
		(start 90.222578 -236.102144)
		(mid 90.500756 -236.032452)
		(end 90.777314 -236.10824)
		(width 0.0889)
		(layer "B.Cu")
		(net "CLK_100M_DB2000_CPU1_BCLK2_DP")
	)
	(arc
		(start 94.536768 -236.10824)
		(mid 94.723966 -236.158383)
		(end 94.911164 -236.10824)
		(width 0.0889)
		(layer "B.Cu")
		(net "CLK_100M_DB2000_CPU1_BCLK2_DP")
	)
	(arc
		(start 90.777314 -236.10824)
		(mid 90.964512 -236.158383)
		(end 91.15171 -236.10824)
		(width 0.0889)
		(layer "B.Cu")
		(net "CLK_100M_DB2000_CPU1_BCLK2_DP")
	)
	(arc
		(start 95.865696 -236.099604)
		(mid 96.142137 -236.032438)
		(end 96.416368 -236.10824)
		(width 0.0889)
		(layer "B.Cu")
		(net "CLK_100M_DB2000_CPU1_BCLK2_DP")
	)
	(arc
		(start 101.115368 -236.10824)
		(mid 101.302566 -236.158383)
		(end 101.489764 -236.10824)
		(width 0.0889)
		(layer "B.Cu")
		(net "CLK_100M_DB2000_CPU1_BCLK2_DP")
	)
	(arc
		(start 89.287096 -236.099604)
		(mid 89.563537 -236.032438)
		(end 89.837768 -236.10824)
		(width 0.0889)
		(layer "B.Cu")
		(net "CLK_100M_DB2000_CPU1_BCLK2_DP")
	)
	(arc
		(start 88.332564 -236.10824)
		(mid 88.615266 -236.032498)
		(end 88.897968 -236.10824)
		(width 0.0889)
		(layer "B.Cu")
		(net "CLK_100M_DB2000_CPU1_BCLK2_DP")
	)
	(arc
		(start 98.295968 -236.10824)
		(mid 98.483166 -236.158383)
		(end 98.670364 -236.10824)
		(width 0.0889)
		(layer "B.Cu")
		(net "CLK_100M_DB2000_CPU1_BCLK2_DP")
	)
	(arc
		(start 101.504496 -236.099604)
		(mid 101.737411 -236.033393)
		(end 101.976682 -236.070648)
		(width 0.0889)
		(layer "B.Cu")
		(net "CLK_100M_DB2000_CPU1_BCLK2_DP")
	)
	(arc
		(start 96.801178 -236.102144)
		(mid 97.079356 -236.032452)
		(end 97.355914 -236.10824)
		(width 0.0889)
		(layer "B.Cu")
		(net "CLK_100M_DB2000_CPU1_BCLK2_DP")
	)
	(arc
		(start 91.717368 -236.10824)
		(mid 91.904566 -236.158383)
		(end 92.091764 -236.10824)
		(width 0.0889)
		(layer "B.Cu")
		(net "CLK_100M_DB2000_CPU1_BCLK2_DP")
	)
	(arc
		(start 87.392764 -236.10824)
		(mid 87.675466 -236.032498)
		(end 87.958168 -236.10824)
		(width 0.0889)
		(layer "B.Cu")
		(net "CLK_100M_DB2000_CPU1_BCLK2_DP")
	)
	(arc
		(start 100.175568 -236.10824)
		(mid 100.362766 -236.158383)
		(end 100.549964 -236.10824)
		(width 0.0889)
		(layer "B.Cu")
		(net "CLK_100M_DB2000_CPU1_BCLK2_DP")
	)
	(arc
		(start 95.476568 -236.10824)
		(mid 95.663766 -236.158383)
		(end 95.850964 -236.10824)
		(width 0.0889)
		(layer "B.Cu")
		(net "CLK_100M_DB2000_CPU1_BCLK2_DP")
	)
	(arc
		(start 88.897968 -236.10824)
		(mid 89.085166 -236.158383)
		(end 89.272364 -236.10824)
		(width 0.0889)
		(layer "B.Cu")
		(net "CLK_100M_DB2000_CPU1_BCLK2_DP")
	)
	(arc
		(start 87.958168 -236.10824)
		(mid 88.145366 -236.158383)
		(end 88.332564 -236.10824)
		(width 0.0889)
		(layer "B.Cu")
		(net "CLK_100M_DB2000_CPU1_BCLK2_DP")
	)
	(arc
		(start 86.931754 -236.91723)
		(mid 87.062668 -236.78087)
		(end 87.110316 -236.597952)
		(width 0.0889)
		(layer "B.Cu")
		(net "CLK_100M_DB2000_CPU1_BCLK2_DP")
	)
	(arc
		(start 93.046296 -236.099604)
		(mid 93.322737 -236.032438)
		(end 93.596968 -236.10824)
		(width 0.0889)
		(layer "B.Cu")
		(net "CLK_100M_DB2000_CPU1_BCLK2_DP")
	)
	(arc
		(start 93.971364 -236.10824)
		(mid 94.254066 -236.032498)
		(end 94.536768 -236.10824)
		(width 0.0889)
		(layer "B.Cu")
		(net "CLK_100M_DB2000_CPU1_BCLK2_DP")
	)
	(arc
		(start 99.235768 -236.10824)
		(mid 99.422966 -236.158383)
		(end 99.610164 -236.10824)
		(width 0.0889)
		(layer "B.Cu")
		(net "CLK_100M_DB2000_CPU1_BCLK2_DP")
	)
	(arc
		(start 96.416368 -236.10824)
		(mid 96.603566 -236.158383)
		(end 96.790764 -236.10824)
		(width 0.0889)
		(layer "B.Cu")
		(net "CLK_100M_DB2000_CPU1_BCLK2_DP")
	)
	(arc
		(start 92.106496 -236.099604)
		(mid 92.382937 -236.032438)
		(end 92.657168 -236.10824)
		(width 0.0889)
		(layer "B.Cu")
		(net "CLK_100M_DB2000_CPU1_BCLK2_DP")
	)
	(arc
		(start 99.624896 -236.099604)
		(mid 99.901337 -236.032438)
		(end 100.175568 -236.10824)
		(width 0.0889)
		(layer "B.Cu")
		(net "CLK_100M_DB2000_CPU1_BCLK2_DP")
	)
	(arc
		(start 100.549964 -236.10824)
		(mid 100.832666 -236.032498)
		(end 101.115368 -236.10824)
		(width 0.0889)
		(layer "B.Cu")
		(net "CLK_100M_DB2000_CPU1_BCLK2_DP")
	)
	(arc
		(start 89.837768 -236.10824)
		(mid 90.024966 -236.158383)
		(end 90.212164 -236.10824)
		(width 0.0889)
		(layer "B.Cu")
		(net "CLK_100M_DB2000_CPU1_BCLK2_DP")
	)
	(arc
		(start 94.925896 -236.099604)
		(mid 95.202337 -236.032438)
		(end 95.476568 -236.10824)
		(width 0.0889)
		(layer "B.Cu")
		(net "CLK_100M_DB2000_CPU1_BCLK2_DP")
	)
	(arc
		(start 97.355914 -236.10824)
		(mid 97.543112 -236.158383)
		(end 97.73031 -236.10824)
		(width 0.0889)
		(layer "B.Cu")
		(net "CLK_100M_DB2000_CPU1_BCLK2_DP")
	)
	(arc
		(start 93.596968 -236.10824)
		(mid 93.784166 -236.158383)
		(end 93.971364 -236.10824)
		(width 0.0889)
		(layer "B.Cu")
		(net "CLK_100M_DB2000_CPU1_BCLK2_DP")
	)
	(arc
		(start 98.685096 -236.099604)
		(mid 98.961537 -236.032438)
		(end 99.235768 -236.10824)
		(width 0.0889)
		(layer "B.Cu")
		(net "CLK_100M_DB2000_CPU1_BCLK2_DP")
	)
	(arc
		(start 91.162124 -236.102144)
		(mid 91.440556 -236.03233)
		(end 91.717368 -236.10824)
		(width 0.0889)
		(layer "B.Cu")
		(net "CLK_100M_DB2000_CPU1_BCLK2_DP")
	)
	(arc
		(start 97.740724 -236.102144)
		(mid 98.019156 -236.03233)
		(end 98.295968 -236.10824)
		(width 0.0889)
		(layer "B.Cu")
		(net "CLK_100M_DB2000_CPU1_BCLK2_DP")
	)
	(segment
		(start 101.772466 -236.598206)
		(end 101.772212 -236.597952)
		(width 0.13208)
		(layer "F.Cu")
		(net "CLK_100M_DB2000_CPU1_BCLK2_DN")
	)
	(segment
		(start 225.58502 -135.283448)
		(end 225.88474 -134.983728)
		(width 0.13208)
		(layer "F.Cu")
		(net "CLK_100M_DB2000_CPU1_BCLK2_DN")
	)
	(segment
		(start 101.772466 -237.133892)
		(end 101.772466 -236.598206)
		(width 0.13208)
		(layer "F.Cu")
		(net "CLK_100M_DB2000_CPU1_BCLK2_DN")
	)
	(segment
		(start 230.732838 -131.441444)
		(end 232.368598 -129.805684)
		(width 0.13208)
		(layer "F.Cu")
		(net "CLK_100M_DB2000_CPU1_BCLK2_DN")
	)
	(segment
		(start 225.88474 -133.669786)
		(end 227.296218 -132.258308)
		(width 0.13208)
		(layer "F.Cu")
		(net "CLK_100M_DB2000_CPU1_BCLK2_DN")
	)
	(segment
		(start 225.88474 -134.983728)
		(end 225.88474 -133.669786)
		(width 0.13208)
		(layer "F.Cu")
		(net "CLK_100M_DB2000_CPU1_BCLK2_DN")
	)
	(segment
		(start 228.76129 -132.258308)
		(end 230.732838 -131.441444)
		(width 0.13208)
		(layer "F.Cu")
		(net "CLK_100M_DB2000_CPU1_BCLK2_DN")
	)
	(segment
		(start 232.368598 -129.805684)
		(end 232.368598 -129.638552)
		(width 0.13208)
		(layer "F.Cu")
		(net "CLK_100M_DB2000_CPU1_BCLK2_DN")
	)
	(segment
		(start 227.296218 -132.258308)
		(end 228.76129 -132.258308)
		(width 0.13208)
		(layer "F.Cu")
		(net "CLK_100M_DB2000_CPU1_BCLK2_DN")
	)
	(segment
		(start 232.368598 -129.638552)
		(end 232.247948 -129.517902)
		(width 0.13208)
		(layer "F.Cu")
		(net "CLK_100M_DB2000_CPU1_BCLK2_DN")
	)
	(via
		(at 101.772212 -236.597952)
		(size 0.4572)
		(drill 0.2032)
		(layers "F.Cu" "B.Cu")
		(net "CLK_100M_DB2000_CPU1_BCLK2_DN")
	)
	(via
		(at 225.58502 -135.283448)
		(size 0.508)
		(drill 0.254)
		(layers "F.Cu" "B.Cu")
		(net "CLK_100M_DB2000_CPU1_BCLK2_DN")
	)
	(segment
		(start 67.633088 -180.835808)
		(end 65.6844 -182.784496)
		(width 0.13208)
		(layer "B.Cu")
		(net "CLK_100M_DB2000_CPU1_BCLK2_DN")
	)
	(segment
		(start 86.830408 -237.42523)
		(end 86.830916 -237.403132)
		(width 0.0889)
		(layer "B.Cu")
		(net "CLK_100M_DB2000_CPU1_BCLK2_DN")
	)
	(segment
		(start 72.266302 -179.397914)
		(end 70.828408 -180.835808)
		(width 0.13208)
		(layer "B.Cu")
		(net "CLK_100M_DB2000_CPU1_BCLK2_DN")
	)
	(segment
		(start 95.931482 -236.28223)
		(end 95.946214 -236.273594)
		(width 0.0889)
		(layer "B.Cu")
		(net "CLK_100M_DB2000_CPU1_BCLK2_DN")
	)
	(segment
		(start 73.107804 -177.442368)
		(end 72.653652 -178.122326)
		(width 0.13208)
		(layer "B.Cu")
		(net "CLK_100M_DB2000_CPU1_BCLK2_DN")
	)
	(segment
		(start 62.84468 -219.767404)
		(end 63.020194 -219.942918)
		(width 0.13208)
		(layer "B.Cu")
		(net "CLK_100M_DB2000_CPU1_BCLK2_DN")
	)
	(segment
		(start 62.940946 -203.604876)
		(end 62.84468 -203.83754)
		(width 0.13208)
		(layer "B.Cu")
		(net "CLK_100M_DB2000_CPU1_BCLK2_DN")
	)
	(segment
		(start 63.893192 -203.04252)
		(end 63.227204 -203.318872)
		(width 0.13208)
		(layer "B.Cu")
		(net "CLK_100M_DB2000_CPU1_BCLK2_DN")
	)
	(segment
		(start 101.928676 -236.32668)
		(end 101.772212 -236.597952)
		(width 0.0889)
		(layer "B.Cu")
		(net "CLK_100M_DB2000_CPU1_BCLK2_DN")
	)
	(segment
		(start 75.948286 -238.12627)
		(end 77.032612 -238.341916)
		(width 0.13208)
		(layer "B.Cu")
		(net "CLK_100M_DB2000_CPU1_BCLK2_DN")
	)
	(segment
		(start 70.828408 -180.835808)
		(end 67.633088 -180.835808)
		(width 0.13208)
		(layer "B.Cu")
		(net "CLK_100M_DB2000_CPU1_BCLK2_DN")
	)
	(segment
		(start 66.542412 -190.432944)
		(end 67.615308 -192.036954)
		(width 0.13208)
		(layer "B.Cu")
		(net "CLK_100M_DB2000_CPU1_BCLK2_DN")
	)
	(segment
		(start 67.615308 -192.036954)
		(end 67.75704 -192.380108)
		(width 0.13208)
		(layer "B.Cu")
		(net "CLK_100M_DB2000_CPU1_BCLK2_DN")
	)
	(segment
		(start 83.538822 -238.341916)
		(end 83.56092 -238.341916)
		(width 0.0889)
		(layer "B.Cu")
		(net "CLK_100M_DB2000_CPU1_BCLK2_DN")
	)
	(segment
		(start 65.6844 -182.784496)
		(end 65.6844 -186.530996)
		(width 0.13208)
		(layer "B.Cu")
		(net "CLK_100M_DB2000_CPU1_BCLK2_DN")
	)
	(segment
		(start 89.3572 -236.27969)
		(end 89.367614 -236.273594)
		(width 0.0889)
		(layer "B.Cu")
		(net "CLK_100M_DB2000_CPU1_BCLK2_DN")
	)
	(segment
		(start 87.021924 -237.085124)
		(end 87.02421 -237.083854)
		(width 0.0889)
		(layer "B.Cu")
		(net "CLK_100M_DB2000_CPU1_BCLK2_DN")
	)
	(segment
		(start 77.21092 -175.509682)
		(end 75.904852 -176.81575)
		(width 0.13208)
		(layer "B.Cu")
		(net "CLK_100M_DB2000_CPU1_BCLK2_DN")
	)
	(segment
		(start 67.180206 -200.416668)
		(end 65.883282 -201.71283)
		(width 0.13208)
		(layer "B.Cu")
		(net "CLK_100M_DB2000_CPU1_BCLK2_DN")
	)
	(segment
		(start 66.384424 -190.049404)
		(end 66.542412 -190.432944)
		(width 0.13208)
		(layer "B.Cu")
		(net "CLK_100M_DB2000_CPU1_BCLK2_DN")
	)
	(segment
		(start 87.018114 -237.08741)
		(end 87.020908 -237.085632)
		(width 0.0889)
		(layer "B.Cu")
		(net "CLK_100M_DB2000_CPU1_BCLK2_DN")
	)
	(segment
		(start 90.292682 -236.28223)
		(end 90.307414 -236.273594)
		(width 0.0889)
		(layer "B.Cu")
		(net "CLK_100M_DB2000_CPU1_BCLK2_DN")
	)
	(segment
		(start 65.711832 -234.466384)
		(end 75.948286 -238.12627)
		(width 0.13208)
		(layer "B.Cu")
		(net "CLK_100M_DB2000_CPU1_BCLK2_DN")
	)
	(segment
		(start 98.750882 -236.28223)
		(end 98.765614 -236.273594)
		(width 0.0889)
		(layer "B.Cu")
		(net "CLK_100M_DB2000_CPU1_BCLK2_DN")
	)
	(segment
		(start 93.112082 -236.28223)
		(end 93.126814 -236.273594)
		(width 0.0889)
		(layer "B.Cu")
		(net "CLK_100M_DB2000_CPU1_BCLK2_DN")
	)
	(segment
		(start 225.88728 -136.321038)
		(end 225.027744 -137.180574)
		(width 0.13208)
		(layer "B.Cu")
		(net "CLK_100M_DB2000_CPU1_BCLK2_DN")
	)
	(segment
		(start 83.596734 -238.306102)
		(end 86.322916 -238.306102)
		(width 0.0889)
		(layer "B.Cu")
		(net "CLK_100M_DB2000_CPU1_BCLK2_DN")
	)
	(segment
		(start 63.020194 -232.133902)
		(end 63.326518 -232.87228)
		(width 0.13208)
		(layer "B.Cu")
		(net "CLK_100M_DB2000_CPU1_BCLK2_DN")
	)
	(segment
		(start 63.326518 -232.87228)
		(end 65.712594 -234.466638)
		(width 0.13208)
		(layer "B.Cu")
		(net "CLK_100M_DB2000_CPU1_BCLK2_DN")
	)
	(segment
		(start 101.907594 -236.248702)
		(end 101.928676 -236.32668)
		(width 0.0889)
		(layer "B.Cu")
		(net "CLK_100M_DB2000_CPU1_BCLK2_DN")
	)
	(segment
		(start 87.020908 -237.085632)
		(end 87.021924 -237.085124)
		(width 0.0889)
		(layer "B.Cu")
		(net "CLK_100M_DB2000_CPU1_BCLK2_DN")
	)
	(segment
		(start 67.75704 -199.023478)
		(end 67.180206 -200.416668)
		(width 0.13208)
		(layer "B.Cu")
		(net "CLK_100M_DB2000_CPU1_BCLK2_DN")
	)
	(segment
		(start 62.84468 -203.83754)
		(end 62.84468 -219.767404)
		(width 0.13208)
		(layer "B.Cu")
		(net "CLK_100M_DB2000_CPU1_BCLK2_DN")
	)
	(segment
		(start 74.622152 -176.81575)
		(end 73.107804 -177.442368)
		(width 0.13208)
		(layer "B.Cu")
		(net "CLK_100M_DB2000_CPU1_BCLK2_DN")
	)
	(segment
		(start 86.322916 -238.306102)
		(end 86.830408 -237.79861)
		(width 0.0889)
		(layer "B.Cu")
		(net "CLK_100M_DB2000_CPU1_BCLK2_DN")
	)
	(segment
		(start 65.6844 -186.530996)
		(end 66.384424 -190.049404)
		(width 0.13208)
		(layer "B.Cu")
		(net "CLK_100M_DB2000_CPU1_BCLK2_DN")
	)
	(segment
		(start 225.58502 -135.283448)
		(end 225.88728 -135.585708)
		(width 0.13208)
		(layer "B.Cu")
		(net "CLK_100M_DB2000_CPU1_BCLK2_DN")
	)
	(segment
		(start 94.056454 -236.27969)
		(end 94.066868 -236.273594)
		(width 0.0889)
		(layer "B.Cu")
		(net "CLK_100M_DB2000_CPU1_BCLK2_DN")
	)
	(segment
		(start 100.635054 -236.27969)
		(end 100.645468 -236.273594)
		(width 0.0889)
		(layer "B.Cu")
		(net "CLK_100M_DB2000_CPU1_BCLK2_DN")
	)
	(segment
		(start 72.653652 -178.122326)
		(end 72.266302 -179.397914)
		(width 0.13208)
		(layer "B.Cu")
		(net "CLK_100M_DB2000_CPU1_BCLK2_DN")
	)
	(segment
		(start 101.567742 -236.283246)
		(end 101.585014 -236.27334)
		(width 0.0889)
		(layer "B.Cu")
		(net "CLK_100M_DB2000_CPU1_BCLK2_DN")
	)
	(segment
		(start 63.227204 -203.318872)
		(end 62.940946 -203.604876)
		(width 0.13208)
		(layer "B.Cu")
		(net "CLK_100M_DB2000_CPU1_BCLK2_DN")
	)
	(segment
		(start 225.88728 -135.585708)
		(end 225.88728 -136.321038)
		(width 0.13208)
		(layer "B.Cu")
		(net "CLK_100M_DB2000_CPU1_BCLK2_DN")
	)
	(segment
		(start 75.904852 -176.81575)
		(end 74.622152 -176.81575)
		(width 0.13208)
		(layer "B.Cu")
		(net "CLK_100M_DB2000_CPU1_BCLK2_DN")
	)
	(segment
		(start 86.830408 -237.79861)
		(end 86.830408 -237.42523)
		(width 0.0889)
		(layer "B.Cu")
		(net "CLK_100M_DB2000_CPU1_BCLK2_DN")
	)
	(segment
		(start 99.690682 -236.28223)
		(end 99.705414 -236.273594)
		(width 0.0889)
		(layer "B.Cu")
		(net "CLK_100M_DB2000_CPU1_BCLK2_DN")
	)
	(segment
		(start 83.56092 -238.341916)
		(end 83.596734 -238.306102)
		(width 0.0889)
		(layer "B.Cu")
		(net "CLK_100M_DB2000_CPU1_BCLK2_DN")
	)
	(segment
		(start 108.573316 -143.060928)
		(end 107.108498 -143.667734)
		(width 0.13208)
		(layer "B.Cu")
		(net "CLK_100M_DB2000_CPU1_BCLK2_DN")
	)
	(segment
		(start 65.883282 -201.71283)
		(end 63.893192 -203.04252)
		(width 0.13208)
		(layer "B.Cu")
		(net "CLK_100M_DB2000_CPU1_BCLK2_DN")
	)
	(segment
		(start 223.204786 -137.543032)
		(end 186.008518 -143.060928)
		(width 0.13208)
		(layer "B.Cu")
		(net "CLK_100M_DB2000_CPU1_BCLK2_DN")
	)
	(segment
		(start 186.008518 -143.060928)
		(end 108.573316 -143.060928)
		(width 0.13208)
		(layer "B.Cu")
		(net "CLK_100M_DB2000_CPU1_BCLK2_DN")
	)
	(segment
		(start 94.996 -236.27969)
		(end 95.006414 -236.273594)
		(width 0.0889)
		(layer "B.Cu")
		(net "CLK_100M_DB2000_CPU1_BCLK2_DN")
	)
	(segment
		(start 87.479378 -236.278674)
		(end 87.488268 -236.273594)
		(width 0.0889)
		(layer "B.Cu")
		(net "CLK_100M_DB2000_CPU1_BCLK2_DN")
	)
	(segment
		(start 63.020194 -219.942918)
		(end 63.020194 -232.133902)
		(width 0.13208)
		(layer "B.Cu")
		(net "CLK_100M_DB2000_CPU1_BCLK2_DN")
	)
	(segment
		(start 225.027744 -137.180574)
		(end 223.204786 -137.543032)
		(width 0.13208)
		(layer "B.Cu")
		(net "CLK_100M_DB2000_CPU1_BCLK2_DN")
	)
	(segment
		(start 65.712594 -234.466638)
		(end 65.711832 -234.466384)
		(width 0.13208)
		(layer "B.Cu")
		(net "CLK_100M_DB2000_CPU1_BCLK2_DN")
	)
	(segment
		(start 107.108498 -143.667734)
		(end 77.21092 -173.565312)
		(width 0.13208)
		(layer "B.Cu")
		(net "CLK_100M_DB2000_CPU1_BCLK2_DN")
	)
	(segment
		(start 92.172282 -236.28223)
		(end 92.187014 -236.273594)
		(width 0.0889)
		(layer "B.Cu")
		(net "CLK_100M_DB2000_CPU1_BCLK2_DN")
	)
	(segment
		(start 67.75704 -192.380108)
		(end 67.75704 -199.023478)
		(width 0.13208)
		(layer "B.Cu")
		(net "CLK_100M_DB2000_CPU1_BCLK2_DN")
	)
	(segment
		(start 77.032612 -238.341916)
		(end 83.538822 -238.341916)
		(width 0.13208)
		(layer "B.Cu")
		(net "CLK_100M_DB2000_CPU1_BCLK2_DN")
	)
	(segment
		(start 96.871282 -236.28223)
		(end 96.886014 -236.273594)
		(width 0.0889)
		(layer "B.Cu")
		(net "CLK_100M_DB2000_CPU1_BCLK2_DN")
	)
	(segment
		(start 77.21092 -173.565312)
		(end 77.21092 -175.509682)
		(width 0.13208)
		(layer "B.Cu")
		(net "CLK_100M_DB2000_CPU1_BCLK2_DN")
	)
	(arc
		(start 89.74201 -236.273594)
		(mid 90.016239 -236.349519)
		(end 90.292682 -236.28223)
		(width 0.0889)
		(layer "B.Cu")
		(net "CLK_100M_DB2000_CPU1_BCLK2_DN")
	)
	(arc
		(start 96.886014 -236.273594)
		(mid 97.073212 -236.223451)
		(end 97.26041 -236.273594)
		(width 0.0889)
		(layer "B.Cu")
		(net "CLK_100M_DB2000_CPU1_BCLK2_DN")
	)
	(arc
		(start 90.68181 -236.273594)
		(mid 90.964512 -236.349336)
		(end 91.247214 -236.273594)
		(width 0.0889)
		(layer "B.Cu")
		(net "CLK_100M_DB2000_CPU1_BCLK2_DN")
	)
	(arc
		(start 99.14001 -236.273594)
		(mid 99.414239 -236.349519)
		(end 99.690682 -236.28223)
		(width 0.0889)
		(layer "B.Cu")
		(net "CLK_100M_DB2000_CPU1_BCLK2_DN")
	)
	(arc
		(start 92.187014 -236.273594)
		(mid 92.374212 -236.223451)
		(end 92.56141 -236.273594)
		(width 0.0889)
		(layer "B.Cu")
		(net "CLK_100M_DB2000_CPU1_BCLK2_DN")
	)
	(arc
		(start 98.765614 -236.273594)
		(mid 98.952812 -236.223451)
		(end 99.14001 -236.273594)
		(width 0.0889)
		(layer "B.Cu")
		(net "CLK_100M_DB2000_CPU1_BCLK2_DN")
	)
	(arc
		(start 100.645468 -236.273594)
		(mid 100.832666 -236.223451)
		(end 101.019864 -236.273594)
		(width 0.0889)
		(layer "B.Cu")
		(net "CLK_100M_DB2000_CPU1_BCLK2_DN")
	)
	(arc
		(start 95.946214 -236.273594)
		(mid 96.133412 -236.223451)
		(end 96.32061 -236.273594)
		(width 0.0889)
		(layer "B.Cu")
		(net "CLK_100M_DB2000_CPU1_BCLK2_DN")
	)
	(arc
		(start 98.20021 -236.273594)
		(mid 98.474439 -236.349519)
		(end 98.750882 -236.28223)
		(width 0.0889)
		(layer "B.Cu")
		(net "CLK_100M_DB2000_CPU1_BCLK2_DN")
	)
	(arc
		(start 86.830916 -237.403132)
		(mid 86.883186 -237.220767)
		(end 87.018114 -237.08741)
		(width 0.0889)
		(layer "B.Cu")
		(net "CLK_100M_DB2000_CPU1_BCLK2_DN")
	)
	(arc
		(start 93.50121 -236.273594)
		(mid 93.778023 -236.34943)
		(end 94.056454 -236.27969)
		(width 0.0889)
		(layer "B.Cu")
		(net "CLK_100M_DB2000_CPU1_BCLK2_DN")
	)
	(arc
		(start 99.705414 -236.273594)
		(mid 99.892612 -236.223451)
		(end 100.07981 -236.273594)
		(width 0.0889)
		(layer "B.Cu")
		(net "CLK_100M_DB2000_CPU1_BCLK2_DN")
	)
	(arc
		(start 95.006414 -236.273594)
		(mid 95.193612 -236.223451)
		(end 95.38081 -236.273594)
		(width 0.0889)
		(layer "B.Cu")
		(net "CLK_100M_DB2000_CPU1_BCLK2_DN")
	)
	(arc
		(start 95.38081 -236.273594)
		(mid 95.655039 -236.349519)
		(end 95.931482 -236.28223)
		(width 0.0889)
		(layer "B.Cu")
		(net "CLK_100M_DB2000_CPU1_BCLK2_DN")
	)
	(arc
		(start 97.825814 -236.273594)
		(mid 98.013012 -236.223451)
		(end 98.20021 -236.273594)
		(width 0.0889)
		(layer "B.Cu")
		(net "CLK_100M_DB2000_CPU1_BCLK2_DN")
	)
	(arc
		(start 100.07981 -236.273594)
		(mid 100.356623 -236.34943)
		(end 100.635054 -236.27969)
		(width 0.0889)
		(layer "B.Cu")
		(net "CLK_100M_DB2000_CPU1_BCLK2_DN")
	)
	(arc
		(start 87.862664 -236.273594)
		(mid 88.145366 -236.349336)
		(end 88.428068 -236.273594)
		(width 0.0889)
		(layer "B.Cu")
		(net "CLK_100M_DB2000_CPU1_BCLK2_DN")
	)
	(arc
		(start 87.02421 -237.083854)
		(mid 87.226797 -236.877503)
		(end 87.300816 -236.597952)
		(width 0.0889)
		(layer "B.Cu")
		(net "CLK_100M_DB2000_CPU1_BCLK2_DN")
	)
	(arc
		(start 88.802464 -236.273594)
		(mid 89.079023 -236.349303)
		(end 89.3572 -236.27969)
		(width 0.0889)
		(layer "B.Cu")
		(net "CLK_100M_DB2000_CPU1_BCLK2_DN")
	)
	(arc
		(start 87.300816 -236.597952)
		(mid 87.348495 -236.415052)
		(end 87.479378 -236.278674)
		(width 0.0889)
		(layer "B.Cu")
		(net "CLK_100M_DB2000_CPU1_BCLK2_DN")
	)
	(arc
		(start 87.488268 -236.273594)
		(mid 87.675466 -236.223451)
		(end 87.862664 -236.273594)
		(width 0.0889)
		(layer "B.Cu")
		(net "CLK_100M_DB2000_CPU1_BCLK2_DN")
	)
	(arc
		(start 96.32061 -236.273594)
		(mid 96.594839 -236.349519)
		(end 96.871282 -236.28223)
		(width 0.0889)
		(layer "B.Cu")
		(net "CLK_100M_DB2000_CPU1_BCLK2_DN")
	)
	(arc
		(start 94.066868 -236.273594)
		(mid 94.254066 -236.223451)
		(end 94.441264 -236.273594)
		(width 0.0889)
		(layer "B.Cu")
		(net "CLK_100M_DB2000_CPU1_BCLK2_DN")
	)
	(arc
		(start 89.367614 -236.273594)
		(mid 89.554812 -236.223451)
		(end 89.74201 -236.273594)
		(width 0.0889)
		(layer "B.Cu")
		(net "CLK_100M_DB2000_CPU1_BCLK2_DN")
	)
	(arc
		(start 101.585014 -236.27334)
		(mid 101.743502 -236.224407)
		(end 101.907594 -236.248702)
		(width 0.0889)
		(layer "B.Cu")
		(net "CLK_100M_DB2000_CPU1_BCLK2_DN")
	)
	(arc
		(start 97.26041 -236.273594)
		(mid 97.543112 -236.349336)
		(end 97.825814 -236.273594)
		(width 0.0889)
		(layer "B.Cu")
		(net "CLK_100M_DB2000_CPU1_BCLK2_DN")
	)
	(arc
		(start 92.56141 -236.273594)
		(mid 92.835639 -236.349519)
		(end 93.112082 -236.28223)
		(width 0.0889)
		(layer "B.Cu")
		(net "CLK_100M_DB2000_CPU1_BCLK2_DN")
	)
	(arc
		(start 90.307414 -236.273594)
		(mid 90.494612 -236.223451)
		(end 90.68181 -236.273594)
		(width 0.0889)
		(layer "B.Cu")
		(net "CLK_100M_DB2000_CPU1_BCLK2_DN")
	)
	(arc
		(start 94.441264 -236.273594)
		(mid 94.717823 -236.349303)
		(end 94.996 -236.27969)
		(width 0.0889)
		(layer "B.Cu")
		(net "CLK_100M_DB2000_CPU1_BCLK2_DN")
	)
	(arc
		(start 93.126814 -236.273594)
		(mid 93.314012 -236.223451)
		(end 93.50121 -236.273594)
		(width 0.0889)
		(layer "B.Cu")
		(net "CLK_100M_DB2000_CPU1_BCLK2_DN")
	)
	(arc
		(start 101.019864 -236.273594)
		(mid 101.292562 -236.349248)
		(end 101.567742 -236.283246)
		(width 0.0889)
		(layer "B.Cu")
		(net "CLK_100M_DB2000_CPU1_BCLK2_DN")
	)
	(arc
		(start 91.62161 -236.273594)
		(mid 91.895839 -236.349519)
		(end 92.172282 -236.28223)
		(width 0.0889)
		(layer "B.Cu")
		(net "CLK_100M_DB2000_CPU1_BCLK2_DN")
	)
	(arc
		(start 88.428068 -236.273594)
		(mid 88.615266 -236.223451)
		(end 88.802464 -236.273594)
		(width 0.0889)
		(layer "B.Cu")
		(net "CLK_100M_DB2000_CPU1_BCLK2_DN")
	)
	(arc
		(start 91.247214 -236.273594)
		(mid 91.434412 -236.223451)
		(end 91.62161 -236.273594)
		(width 0.0889)
		(layer "B.Cu")
		(net "CLK_100M_DB2000_CPU1_BCLK2_DN")
	)
	(segment
		(start 121.508266 -236.598206)
		(end 121.508012 -236.597952)
		(width 0.13208)
		(layer "F.Cu")
		(net "CLK_100M_DB2000_CPU1_BCLK1_DP")
	)
	(segment
		(start 233.629962 -129.638552)
		(end 233.629962 -129.636012)
		(width 0.13208)
		(layer "F.Cu")
		(net "CLK_100M_DB2000_CPU1_BCLK1_DP")
	)
	(segment
		(start 233.629962 -129.636012)
		(end 233.748072 -129.517902)
		(width 0.13208)
		(layer "F.Cu")
		(net "CLK_100M_DB2000_CPU1_BCLK1_DP")
	)
	(segment
		(start 121.508266 -237.133892)
		(end 121.508266 -236.598206)
		(width 0.13208)
		(layer "F.Cu")
		(net "CLK_100M_DB2000_CPU1_BCLK1_DP")
	)
	(segment
		(start 232.5624 -131.622546)
		(end 233.630216 -130.55473)
		(width 0.13208)
		(layer "F.Cu")
		(net "CLK_100M_DB2000_CPU1_BCLK1_DP")
	)
	(segment
		(start 233.630216 -129.638806)
		(end 233.629962 -129.638552)
		(width 0.13208)
		(layer "F.Cu")
		(net "CLK_100M_DB2000_CPU1_BCLK1_DP")
	)
	(segment
		(start 232.865676 -132.502148)
		(end 232.5624 -132.198872)
		(width 0.13208)
		(layer "F.Cu")
		(net "CLK_100M_DB2000_CPU1_BCLK1_DP")
	)
	(segment
		(start 232.5624 -132.198872)
		(end 232.5624 -131.622546)
		(width 0.13208)
		(layer "F.Cu")
		(net "CLK_100M_DB2000_CPU1_BCLK1_DP")
	)
	(segment
		(start 233.630216 -130.55473)
		(end 233.630216 -129.638806)
		(width 0.13208)
		(layer "F.Cu")
		(net "CLK_100M_DB2000_CPU1_BCLK1_DP")
	)
	(via
		(at 121.508012 -236.597952)
		(size 0.4572)
		(drill 0.2032)
		(layers "F.Cu" "B.Cu")
		(net "CLK_100M_DB2000_CPU1_BCLK1_DP")
	)
	(via
		(at 232.865676 -132.502148)
		(size 0.508)
		(drill 0.254)
		(layers "F.Cu" "B.Cu")
		(net "CLK_100M_DB2000_CPU1_BCLK1_DP")
	)
	(segment
		(start 163.4998 -190.581788)
		(end 163.4998 -197.030086)
		(width 0.13208)
		(layer "B.Cu")
		(net "CLK_100M_DB2000_CPU1_BCLK1_DP")
	)
	(segment
		(start 148.036534 -237.281466)
		(end 137.570718 -237.281466)
		(width 0.13208)
		(layer "B.Cu")
		(net "CLK_100M_DB2000_CPU1_BCLK1_DP")
	)
	(segment
		(start 231.707436 -137.09015)
		(end 230.014018 -138.783568)
		(width 0.13208)
		(layer "B.Cu")
		(net "CLK_100M_DB2000_CPU1_BCLK1_DP")
	)
	(segment
		(start 232.55986 -135.033512)
		(end 231.707436 -137.09015)
		(width 0.13208)
		(layer "B.Cu")
		(net "CLK_100M_DB2000_CPU1_BCLK1_DP")
	)
	(segment
		(start 137.54862 -237.281466)
		(end 137.514076 -237.246922)
		(width 0.0889)
		(layer "B.Cu")
		(net "CLK_100M_DB2000_CPU1_BCLK1_DP")
	)
	(segment
		(start 133.538468 -236.273594)
		(end 133.528054 -236.27969)
		(width 0.0889)
		(layer "B.Cu")
		(net "CLK_100M_DB2000_CPU1_BCLK1_DP")
	)
	(segment
		(start 121.664476 -236.326934)
		(end 121.508012 -236.597952)
		(width 0.0889)
		(layer "B.Cu")
		(net "CLK_100M_DB2000_CPU1_BCLK1_DP")
	)
	(segment
		(start 135.039862 -236.597952)
		(end 135.039862 -236.589316)
		(width 0.0889)
		(layer "B.Cu")
		(net "CLK_100M_DB2000_CPU1_BCLK1_DP")
	)
	(segment
		(start 160.18891 -232.178352)
		(end 158.383986 -233.384598)
		(width 0.13208)
		(layer "B.Cu")
		(net "CLK_100M_DB2000_CPU1_BCLK1_DP")
	)
	(segment
		(start 131.658614 -236.273594)
		(end 131.643882 -236.28223)
		(width 0.0889)
		(layer "B.Cu")
		(net "CLK_100M_DB2000_CPU1_BCLK1_DP")
	)
	(segment
		(start 137.514076 -237.246922)
		(end 135.91667 -237.246922)
		(width 0.0889)
		(layer "B.Cu")
		(net "CLK_100M_DB2000_CPU1_BCLK1_DP")
	)
	(segment
		(start 137.570718 -237.281466)
		(end 137.54862 -237.281466)
		(width 0.0889)
		(layer "B.Cu")
		(net "CLK_100M_DB2000_CPU1_BCLK1_DP")
	)
	(segment
		(start 230.014018 -138.783568)
		(end 197.537324 -145.243296)
		(width 0.13208)
		(layer "B.Cu")
		(net "CLK_100M_DB2000_CPU1_BCLK1_DP")
	)
	(segment
		(start 197.537324 -145.243296)
		(end 190.336424 -148.226018)
		(width 0.13208)
		(layer "B.Cu")
		(net "CLK_100M_DB2000_CPU1_BCLK1_DP")
	)
	(segment
		(start 130.718814 -236.273594)
		(end 130.704082 -236.28223)
		(width 0.0889)
		(layer "B.Cu")
		(net "CLK_100M_DB2000_CPU1_BCLK1_DP")
	)
	(segment
		(start 127.899414 -236.273594)
		(end 127.884682 -236.28223)
		(width 0.0889)
		(layer "B.Cu")
		(net "CLK_100M_DB2000_CPU1_BCLK1_DP")
	)
	(segment
		(start 232.55986 -132.807964)
		(end 232.55986 -135.033512)
		(width 0.13208)
		(layer "B.Cu")
		(net "CLK_100M_DB2000_CPU1_BCLK1_DP")
	)
	(segment
		(start 161.037778 -200.679812)
		(end 161.037778 -231.32923)
		(width 0.13208)
		(layer "B.Cu")
		(net "CLK_100M_DB2000_CPU1_BCLK1_DP")
	)
	(segment
		(start 232.865676 -132.502148)
		(end 232.55986 -132.807964)
		(width 0.13208)
		(layer "B.Cu")
		(net "CLK_100M_DB2000_CPU1_BCLK1_DP")
	)
	(segment
		(start 158.383986 -233.384598)
		(end 156.349192 -235.419138)
		(width 0.13208)
		(layer "B.Cu")
		(net "CLK_100M_DB2000_CPU1_BCLK1_DP")
	)
	(segment
		(start 155.685744 -235.69422)
		(end 151.86914 -235.69422)
		(width 0.13208)
		(layer "B.Cu")
		(net "CLK_100M_DB2000_CPU1_BCLK1_DP")
	)
	(segment
		(start 163.4998 -197.030086)
		(end 162.659568 -199.058022)
		(width 0.13208)
		(layer "B.Cu")
		(net "CLK_100M_DB2000_CPU1_BCLK1_DP")
	)
	(segment
		(start 156.349192 -235.419138)
		(end 155.685744 -235.69422)
		(width 0.13208)
		(layer "B.Cu")
		(net "CLK_100M_DB2000_CPU1_BCLK1_DP")
	)
	(segment
		(start 122.260868 -236.273594)
		(end 122.250454 -236.27969)
		(width 0.0889)
		(layer "B.Cu")
		(net "CLK_100M_DB2000_CPU1_BCLK1_DP")
	)
	(segment
		(start 179.550568 -159.012636)
		(end 171.726352 -170.722544)
		(width 0.13208)
		(layer "B.Cu")
		(net "CLK_100M_DB2000_CPU1_BCLK1_DP")
	)
	(segment
		(start 151.86914 -235.69422)
		(end 148.036534 -237.281466)
		(width 0.13208)
		(layer "B.Cu")
		(net "CLK_100M_DB2000_CPU1_BCLK1_DP")
	)
	(segment
		(start 123.200414 -236.273594)
		(end 123.19 -236.27969)
		(width 0.0889)
		(layer "B.Cu")
		(net "CLK_100M_DB2000_CPU1_BCLK1_DP")
	)
	(segment
		(start 129.779014 -236.273594)
		(end 129.7686 -236.27969)
		(width 0.0889)
		(layer "B.Cu")
		(net "CLK_100M_DB2000_CPU1_BCLK1_DP")
	)
	(segment
		(start 190.336424 -148.226018)
		(end 179.550568 -159.012636)
		(width 0.13208)
		(layer "B.Cu")
		(net "CLK_100M_DB2000_CPU1_BCLK1_DP")
	)
	(segment
		(start 135.32231 -237.086648)
		(end 135.316468 -237.083854)
		(width 0.0889)
		(layer "B.Cu")
		(net "CLK_100M_DB2000_CPU1_BCLK1_DP")
	)
	(segment
		(start 162.659568 -199.058022)
		(end 161.037778 -200.679812)
		(width 0.13208)
		(layer "B.Cu")
		(net "CLK_100M_DB2000_CPU1_BCLK1_DP")
	)
	(segment
		(start 171.726352 -170.722544)
		(end 163.4998 -190.581788)
		(width 0.13208)
		(layer "B.Cu")
		(net "CLK_100M_DB2000_CPU1_BCLK1_DP")
	)
	(segment
		(start 124.140214 -236.273594)
		(end 124.125482 -236.28223)
		(width 0.0889)
		(layer "B.Cu")
		(net "CLK_100M_DB2000_CPU1_BCLK1_DP")
	)
	(segment
		(start 121.75363 -236.303058)
		(end 121.664476 -236.326934)
		(width 0.0889)
		(layer "B.Cu")
		(net "CLK_100M_DB2000_CPU1_BCLK1_DP")
	)
	(segment
		(start 160.775904 -231.591358)
		(end 160.18891 -232.178352)
		(width 0.13208)
		(layer "B.Cu")
		(net "CLK_100M_DB2000_CPU1_BCLK1_DP")
	)
	(segment
		(start 126.959614 -236.273594)
		(end 126.944882 -236.28223)
		(width 0.0889)
		(layer "B.Cu")
		(net "CLK_100M_DB2000_CPU1_BCLK1_DP")
	)
	(segment
		(start 161.037778 -231.32923)
		(end 160.775904 -231.591358)
		(width 0.13208)
		(layer "B.Cu")
		(net "CLK_100M_DB2000_CPU1_BCLK1_DP")
	)
	(segment
		(start 125.080014 -236.273594)
		(end 125.065282 -236.28223)
		(width 0.0889)
		(layer "B.Cu")
		(net "CLK_100M_DB2000_CPU1_BCLK1_DP")
	)
	(segment
		(start 128.839468 -236.273594)
		(end 128.829054 -236.27969)
		(width 0.0889)
		(layer "B.Cu")
		(net "CLK_100M_DB2000_CPU1_BCLK1_DP")
	)
	(arc
		(start 124.51461 -236.273594)
		(mid 124.327412 -236.223451)
		(end 124.140214 -236.273594)
		(width 0.0889)
		(layer "B.Cu")
		(net "CLK_100M_DB2000_CPU1_BCLK1_DP")
	)
	(arc
		(start 134.478268 -236.273594)
		(mid 134.195566 -236.349336)
		(end 133.912864 -236.273594)
		(width 0.0889)
		(layer "B.Cu")
		(net "CLK_100M_DB2000_CPU1_BCLK1_DP")
	)
	(arc
		(start 128.829054 -236.27969)
		(mid 128.550622 -236.349504)
		(end 128.27381 -236.273594)
		(width 0.0889)
		(layer "B.Cu")
		(net "CLK_100M_DB2000_CPU1_BCLK1_DP")
	)
	(arc
		(start 122.635264 -236.273594)
		(mid 122.448066 -236.223451)
		(end 122.260868 -236.273594)
		(width 0.0889)
		(layer "B.Cu")
		(net "CLK_100M_DB2000_CPU1_BCLK1_DP")
	)
	(arc
		(start 121.773696 -236.311186)
		(mid 121.763624 -236.307219)
		(end 121.75363 -236.303058)
		(width 0.0889)
		(layer "B.Cu")
		(net "CLK_100M_DB2000_CPU1_BCLK1_DP")
	)
	(arc
		(start 125.45441 -236.273594)
		(mid 125.267212 -236.223451)
		(end 125.080014 -236.273594)
		(width 0.0889)
		(layer "B.Cu")
		(net "CLK_100M_DB2000_CPU1_BCLK1_DP")
	)
	(arc
		(start 122.250454 -236.27969)
		(mid 122.015557 -236.348301)
		(end 121.773696 -236.311186)
		(width 0.0889)
		(layer "B.Cu")
		(net "CLK_100M_DB2000_CPU1_BCLK1_DP")
	)
	(arc
		(start 132.598414 -236.273594)
		(mid 132.315712 -236.349336)
		(end 132.03301 -236.273594)
		(width 0.0889)
		(layer "B.Cu")
		(net "CLK_100M_DB2000_CPU1_BCLK1_DP")
	)
	(arc
		(start 123.57481 -236.273594)
		(mid 123.387612 -236.223451)
		(end 123.200414 -236.273594)
		(width 0.0889)
		(layer "B.Cu")
		(net "CLK_100M_DB2000_CPU1_BCLK1_DP")
	)
	(arc
		(start 128.27381 -236.273594)
		(mid 128.086612 -236.223451)
		(end 127.899414 -236.273594)
		(width 0.0889)
		(layer "B.Cu")
		(net "CLK_100M_DB2000_CPU1_BCLK1_DP")
	)
	(arc
		(start 135.039862 -236.589316)
		(mid 134.848988 -236.271507)
		(end 134.478268 -236.273594)
		(width 0.0889)
		(layer "B.Cu")
		(net "CLK_100M_DB2000_CPU1_BCLK1_DP")
	)
	(arc
		(start 131.09321 -236.273594)
		(mid 130.906012 -236.223451)
		(end 130.718814 -236.273594)
		(width 0.0889)
		(layer "B.Cu")
		(net "CLK_100M_DB2000_CPU1_BCLK1_DP")
	)
	(arc
		(start 135.91667 -237.246922)
		(mid 135.608888 -237.20611)
		(end 135.32231 -237.086648)
		(width 0.0889)
		(layer "B.Cu")
		(net "CLK_100M_DB2000_CPU1_BCLK1_DP")
	)
	(arc
		(start 131.643882 -236.28223)
		(mid 131.367441 -236.349396)
		(end 131.09321 -236.273594)
		(width 0.0889)
		(layer "B.Cu")
		(net "CLK_100M_DB2000_CPU1_BCLK1_DP")
	)
	(arc
		(start 126.944882 -236.28223)
		(mid 126.668441 -236.349396)
		(end 126.39421 -236.273594)
		(width 0.0889)
		(layer "B.Cu")
		(net "CLK_100M_DB2000_CPU1_BCLK1_DP")
	)
	(arc
		(start 125.065282 -236.28223)
		(mid 124.788841 -236.349396)
		(end 124.51461 -236.273594)
		(width 0.0889)
		(layer "B.Cu")
		(net "CLK_100M_DB2000_CPU1_BCLK1_DP")
	)
	(arc
		(start 132.97281 -236.273594)
		(mid 132.785612 -236.223451)
		(end 132.598414 -236.273594)
		(width 0.0889)
		(layer "B.Cu")
		(net "CLK_100M_DB2000_CPU1_BCLK1_DP")
	)
	(arc
		(start 127.33401 -236.273594)
		(mid 127.146812 -236.223451)
		(end 126.959614 -236.273594)
		(width 0.0889)
		(layer "B.Cu")
		(net "CLK_100M_DB2000_CPU1_BCLK1_DP")
	)
	(arc
		(start 129.213864 -236.273594)
		(mid 129.026666 -236.223451)
		(end 128.839468 -236.273594)
		(width 0.0889)
		(layer "B.Cu")
		(net "CLK_100M_DB2000_CPU1_BCLK1_DP")
	)
	(arc
		(start 135.316468 -237.083854)
		(mid 135.113881 -236.877503)
		(end 135.039862 -236.597952)
		(width 0.0889)
		(layer "B.Cu")
		(net "CLK_100M_DB2000_CPU1_BCLK1_DP")
	)
	(arc
		(start 126.39421 -236.273594)
		(mid 126.207012 -236.223451)
		(end 126.019814 -236.273594)
		(width 0.0889)
		(layer "B.Cu")
		(net "CLK_100M_DB2000_CPU1_BCLK1_DP")
	)
	(arc
		(start 127.884682 -236.28223)
		(mid 127.608241 -236.349396)
		(end 127.33401 -236.273594)
		(width 0.0889)
		(layer "B.Cu")
		(net "CLK_100M_DB2000_CPU1_BCLK1_DP")
	)
	(arc
		(start 129.7686 -236.27969)
		(mid 129.490422 -236.349382)
		(end 129.213864 -236.273594)
		(width 0.0889)
		(layer "B.Cu")
		(net "CLK_100M_DB2000_CPU1_BCLK1_DP")
	)
	(arc
		(start 123.19 -236.27969)
		(mid 122.911822 -236.349382)
		(end 122.635264 -236.273594)
		(width 0.0889)
		(layer "B.Cu")
		(net "CLK_100M_DB2000_CPU1_BCLK1_DP")
	)
	(arc
		(start 130.15341 -236.273594)
		(mid 129.966212 -236.223451)
		(end 129.779014 -236.273594)
		(width 0.0889)
		(layer "B.Cu")
		(net "CLK_100M_DB2000_CPU1_BCLK1_DP")
	)
	(arc
		(start 132.03301 -236.273594)
		(mid 131.845812 -236.223451)
		(end 131.658614 -236.273594)
		(width 0.0889)
		(layer "B.Cu")
		(net "CLK_100M_DB2000_CPU1_BCLK1_DP")
	)
	(arc
		(start 126.019814 -236.273594)
		(mid 125.737112 -236.349336)
		(end 125.45441 -236.273594)
		(width 0.0889)
		(layer "B.Cu")
		(net "CLK_100M_DB2000_CPU1_BCLK1_DP")
	)
	(arc
		(start 133.528054 -236.27969)
		(mid 133.249622 -236.349504)
		(end 132.97281 -236.273594)
		(width 0.0889)
		(layer "B.Cu")
		(net "CLK_100M_DB2000_CPU1_BCLK1_DP")
	)
	(arc
		(start 124.125482 -236.28223)
		(mid 123.849041 -236.349396)
		(end 123.57481 -236.273594)
		(width 0.0889)
		(layer "B.Cu")
		(net "CLK_100M_DB2000_CPU1_BCLK1_DP")
	)
	(arc
		(start 130.704082 -236.28223)
		(mid 130.427641 -236.349396)
		(end 130.15341 -236.273594)
		(width 0.0889)
		(layer "B.Cu")
		(net "CLK_100M_DB2000_CPU1_BCLK1_DP")
	)
	(arc
		(start 133.912864 -236.273594)
		(mid 133.725666 -236.223451)
		(end 133.538468 -236.273594)
		(width 0.0889)
		(layer "B.Cu")
		(net "CLK_100M_DB2000_CPU1_BCLK1_DP")
	)
	(segment
		(start 232.30332 -132.200904)
		(end 232.30332 -131.515104)
		(width 0.13208)
		(layer "F.Cu")
		(net "CLK_100M_DB2000_CPU1_BCLK1_DN")
	)
	(segment
		(start 121.977912 -236.319822)
		(end 121.978166 -236.319568)
		(width 0.13208)
		(layer "F.Cu")
		(net "CLK_100M_DB2000_CPU1_BCLK1_DN")
	)
	(segment
		(start 233.371136 -130.447288)
		(end 233.371136 -129.641346)
		(width 0.13208)
		(layer "F.Cu")
		(net "CLK_100M_DB2000_CPU1_BCLK1_DN")
	)
	(segment
		(start 233.368596 -129.638806)
		(end 233.368596 -129.638552)
		(width 0.13208)
		(layer "F.Cu")
		(net "CLK_100M_DB2000_CPU1_BCLK1_DN")
	)
	(segment
		(start 233.368596 -129.638552)
		(end 233.247946 -129.517902)
		(width 0.13208)
		(layer "F.Cu")
		(net "CLK_100M_DB2000_CPU1_BCLK1_DN")
	)
	(segment
		(start 232.30332 -131.515104)
		(end 233.371136 -130.447288)
		(width 0.13208)
		(layer "F.Cu")
		(net "CLK_100M_DB2000_CPU1_BCLK1_DN")
	)
	(segment
		(start 232.002076 -132.502148)
		(end 232.30332 -132.200904)
		(width 0.13208)
		(layer "F.Cu")
		(net "CLK_100M_DB2000_CPU1_BCLK1_DN")
	)
	(segment
		(start 121.978166 -236.319568)
		(end 121.978166 -235.783882)
		(width 0.13208)
		(layer "F.Cu")
		(net "CLK_100M_DB2000_CPU1_BCLK1_DN")
	)
	(segment
		(start 233.371136 -129.641346)
		(end 233.368596 -129.638806)
		(width 0.13208)
		(layer "F.Cu")
		(net "CLK_100M_DB2000_CPU1_BCLK1_DN")
	)
	(via
		(at 232.002076 -132.502148)
		(size 0.508)
		(drill 0.254)
		(layers "F.Cu" "B.Cu")
		(net "CLK_100M_DB2000_CPU1_BCLK1_DN")
	)
	(via
		(at 121.978166 -235.783882)
		(size 0.4572)
		(drill 0.2032)
		(layers "F.Cu" "B.Cu")
		(net "CLK_100M_DB2000_CPU1_BCLK1_DN")
	)
	(segment
		(start 154.49042 -235.31322)
		(end 154.09926 -235.31322)
		(width 0.13208)
		(layer "B.Cu")
		(net "CLK_100M_DB2000_CPU1_BCLK1_DN")
	)
	(segment
		(start 232.30078 -134.981696)
		(end 231.487726 -136.943338)
		(width 0.13208)
		(layer "B.Cu")
		(net "CLK_100M_DB2000_CPU1_BCLK1_DN")
	)
	(segment
		(start 162.439858 -198.91121)
		(end 160.778698 -200.57237)
		(width 0.13208)
		(layer "B.Cu")
		(net "CLK_100M_DB2000_CPU1_BCLK1_DN")
	)
	(segment
		(start 131.573778 -236.102144)
		(end 131.563364 -236.10824)
		(width 0.0889)
		(layer "B.Cu")
		(net "CLK_100M_DB2000_CPU1_BCLK1_DN")
	)
	(segment
		(start 156.970222 -234.24134)
		(end 156.714952 -234.49661)
		(width 0.13208)
		(layer "B.Cu")
		(net "CLK_100M_DB2000_CPU1_BCLK1_DN")
	)
	(segment
		(start 125.934724 -236.102144)
		(end 125.92431 -236.10824)
		(width 0.0889)
		(layer "B.Cu")
		(net "CLK_100M_DB2000_CPU1_BCLK1_DN")
	)
	(segment
		(start 149.600412 -236.35335)
		(end 147.984972 -237.022386)
		(width 0.13208)
		(layer "B.Cu")
		(net "CLK_100M_DB2000_CPU1_BCLK1_DN")
	)
	(segment
		(start 152.98166 -235.43514)
		(end 152.85974 -235.31322)
		(width 0.13208)
		(layer "B.Cu")
		(net "CLK_100M_DB2000_CPU1_BCLK1_DN")
	)
	(segment
		(start 160.778698 -200.57237)
		(end 160.778698 -231.221788)
		(width 0.13208)
		(layer "B.Cu")
		(net "CLK_100M_DB2000_CPU1_BCLK1_DN")
	)
	(segment
		(start 193.837306 -146.495262)
		(end 193.83756 -146.495262)
		(width 0.13208)
		(layer "B.Cu")
		(net "CLK_100M_DB2000_CPU1_BCLK1_DN")
	)
	(segment
		(start 147.984972 -237.022386)
		(end 137.570718 -237.022386)
		(width 0.13208)
		(layer "B.Cu")
		(net "CLK_100M_DB2000_CPU1_BCLK1_DN")
	)
	(segment
		(start 152.34666 -235.43514)
		(end 151.817578 -235.43514)
		(width 0.13208)
		(layer "B.Cu")
		(net "CLK_100M_DB2000_CPU1_BCLK1_DN")
	)
	(segment
		(start 153.97734 -235.43514)
		(end 152.98166 -235.43514)
		(width 0.13208)
		(layer "B.Cu")
		(net "CLK_100M_DB2000_CPU1_BCLK1_DN")
	)
	(segment
		(start 179.349146 -158.847282)
		(end 171.496482 -170.599608)
		(width 0.13208)
		(layer "B.Cu")
		(net "CLK_100M_DB2000_CPU1_BCLK1_DN")
	)
	(segment
		(start 135.417814 -236.922056)
		(end 135.40994 -236.917484)
		(width 0.0889)
		(layer "B.Cu")
		(net "CLK_100M_DB2000_CPU1_BCLK1_DN")
	)
	(segment
		(start 154.61234 -235.43514)
		(end 154.49042 -235.31322)
		(width 0.13208)
		(layer "B.Cu")
		(net "CLK_100M_DB2000_CPU1_BCLK1_DN")
	)
	(segment
		(start 155.633928 -235.43514)
		(end 154.61234 -235.43514)
		(width 0.13208)
		(layer "B.Cu")
		(net "CLK_100M_DB2000_CPU1_BCLK1_DN")
	)
	(segment
		(start 160.023556 -231.97693)
		(end 158.218632 -233.183176)
		(width 0.13208)
		(layer "B.Cu")
		(net "CLK_100M_DB2000_CPU1_BCLK1_DN")
	)
	(segment
		(start 151.817578 -235.43514)
		(end 150.178008 -236.114082)
		(width 0.13208)
		(layer "B.Cu")
		(net "CLK_100M_DB2000_CPU1_BCLK1_DN")
	)
	(segment
		(start 190.189612 -148.006308)
		(end 179.349146 -158.847282)
		(width 0.13208)
		(layer "B.Cu")
		(net "CLK_100M_DB2000_CPU1_BCLK1_DN")
	)
	(segment
		(start 137.54862 -237.022386)
		(end 137.51433 -237.056676)
		(width 0.0889)
		(layer "B.Cu")
		(net "CLK_100M_DB2000_CPU1_BCLK1_DN")
	)
	(segment
		(start 197.461632 -144.994122)
		(end 193.837306 -146.495262)
		(width 0.13208)
		(layer "B.Cu")
		(net "CLK_100M_DB2000_CPU1_BCLK1_DN")
	)
	(segment
		(start 163.24072 -196.978524)
		(end 162.439858 -198.91121)
		(width 0.13208)
		(layer "B.Cu")
		(net "CLK_100M_DB2000_CPU1_BCLK1_DN")
	)
	(segment
		(start 137.570718 -237.022386)
		(end 137.54862 -237.022386)
		(width 0.0889)
		(layer "B.Cu")
		(net "CLK_100M_DB2000_CPU1_BCLK1_DN")
	)
	(segment
		(start 231.487726 -136.943338)
		(end 229.886256 -138.544554)
		(width 0.13208)
		(layer "B.Cu")
		(net "CLK_100M_DB2000_CPU1_BCLK1_DN")
	)
	(segment
		(start 123.119896 -236.099604)
		(end 123.105164 -236.10824)
		(width 0.0889)
		(layer "B.Cu")
		(net "CLK_100M_DB2000_CPU1_BCLK1_DN")
	)
	(segment
		(start 135.230616 -236.597952)
		(end 135.230616 -236.57941)
		(width 0.0889)
		(layer "B.Cu")
		(net "CLK_100M_DB2000_CPU1_BCLK1_DN")
	)
	(segment
		(start 127.818896 -236.099604)
		(end 127.804164 -236.10824)
		(width 0.0889)
		(layer "B.Cu")
		(net "CLK_100M_DB2000_CPU1_BCLK1_DN")
	)
	(segment
		(start 171.496482 -170.599608)
		(end 163.24072 -190.530226)
		(width 0.13208)
		(layer "B.Cu")
		(net "CLK_100M_DB2000_CPU1_BCLK1_DN")
	)
	(segment
		(start 157.160468 -234.24134)
		(end 156.970222 -234.24134)
		(width 0.13208)
		(layer "B.Cu")
		(net "CLK_100M_DB2000_CPU1_BCLK1_DN")
	)
	(segment
		(start 232.30078 -132.800852)
		(end 232.30078 -134.981696)
		(width 0.13208)
		(layer "B.Cu")
		(net "CLK_100M_DB2000_CPU1_BCLK1_DN")
	)
	(segment
		(start 132.513324 -236.102144)
		(end 132.50291 -236.10824)
		(width 0.0889)
		(layer "B.Cu")
		(net "CLK_100M_DB2000_CPU1_BCLK1_DN")
	)
	(segment
		(start 121.842784 -236.132878)
		(end 121.821702 -236.0549)
		(width 0.0889)
		(layer "B.Cu")
		(net "CLK_100M_DB2000_CPU1_BCLK1_DN")
	)
	(segment
		(start 229.886256 -138.544554)
		(end 197.461632 -144.994122)
		(width 0.13208)
		(layer "B.Cu")
		(net "CLK_100M_DB2000_CPU1_BCLK1_DN")
	)
	(segment
		(start 156.20238 -235.199428)
		(end 155.633928 -235.43514)
		(width 0.13208)
		(layer "B.Cu")
		(net "CLK_100M_DB2000_CPU1_BCLK1_DN")
	)
	(segment
		(start 163.24072 -190.530226)
		(end 163.24072 -196.978524)
		(width 0.13208)
		(layer "B.Cu")
		(net "CLK_100M_DB2000_CPU1_BCLK1_DN")
	)
	(segment
		(start 232.002076 -132.502148)
		(end 232.30078 -132.800852)
		(width 0.13208)
		(layer "B.Cu")
		(net "CLK_100M_DB2000_CPU1_BCLK1_DN")
	)
	(segment
		(start 150.01875 -236.048042)
		(end 149.666452 -236.193838)
		(width 0.13208)
		(layer "B.Cu")
		(net "CLK_100M_DB2000_CPU1_BCLK1_DN")
	)
	(segment
		(start 150.178008 -236.114082)
		(end 150.01875 -236.048042)
		(width 0.13208)
		(layer "B.Cu")
		(net "CLK_100M_DB2000_CPU1_BCLK1_DN")
	)
	(segment
		(start 156.714952 -234.49661)
		(end 156.714952 -234.686856)
		(width 0.13208)
		(layer "B.Cu")
		(net "CLK_100M_DB2000_CPU1_BCLK1_DN")
	)
	(segment
		(start 158.218632 -233.183176)
		(end 157.160468 -234.24134)
		(width 0.13208)
		(layer "B.Cu")
		(net "CLK_100M_DB2000_CPU1_BCLK1_DN")
	)
	(segment
		(start 156.714952 -234.686856)
		(end 156.20238 -235.199428)
		(width 0.13208)
		(layer "B.Cu")
		(net "CLK_100M_DB2000_CPU1_BCLK1_DN")
	)
	(segment
		(start 129.698496 -236.099604)
		(end 129.683764 -236.10824)
		(width 0.0889)
		(layer "B.Cu")
		(net "CLK_100M_DB2000_CPU1_BCLK1_DN")
	)
	(segment
		(start 121.821702 -236.0549)
		(end 121.978166 -235.783882)
		(width 0.0889)
		(layer "B.Cu")
		(net "CLK_100M_DB2000_CPU1_BCLK1_DN")
	)
	(segment
		(start 124.995178 -236.102144)
		(end 124.984764 -236.10824)
		(width 0.0889)
		(layer "B.Cu")
		(net "CLK_100M_DB2000_CPU1_BCLK1_DN")
	)
	(segment
		(start 149.666452 -236.193838)
		(end 149.600412 -236.35335)
		(width 0.13208)
		(layer "B.Cu")
		(net "CLK_100M_DB2000_CPU1_BCLK1_DN")
	)
	(segment
		(start 130.638296 -236.099604)
		(end 130.623564 -236.10824)
		(width 0.0889)
		(layer "B.Cu")
		(net "CLK_100M_DB2000_CPU1_BCLK1_DN")
	)
	(segment
		(start 160.778698 -231.221788)
		(end 160.023556 -231.97693)
		(width 0.13208)
		(layer "B.Cu")
		(net "CLK_100M_DB2000_CPU1_BCLK1_DN")
	)
	(segment
		(start 193.83756 -146.495262)
		(end 190.189612 -148.006308)
		(width 0.13208)
		(layer "B.Cu")
		(net "CLK_100M_DB2000_CPU1_BCLK1_DN")
	)
	(segment
		(start 152.46858 -235.31322)
		(end 152.34666 -235.43514)
		(width 0.13208)
		(layer "B.Cu")
		(net "CLK_100M_DB2000_CPU1_BCLK1_DN")
	)
	(segment
		(start 126.879096 -236.099604)
		(end 126.864364 -236.10824)
		(width 0.0889)
		(layer "B.Cu")
		(net "CLK_100M_DB2000_CPU1_BCLK1_DN")
	)
	(segment
		(start 154.09926 -235.31322)
		(end 153.97734 -235.43514)
		(width 0.13208)
		(layer "B.Cu")
		(net "CLK_100M_DB2000_CPU1_BCLK1_DN")
	)
	(segment
		(start 137.51433 -237.056676)
		(end 135.916924 -237.056676)
		(width 0.0889)
		(layer "B.Cu")
		(net "CLK_100M_DB2000_CPU1_BCLK1_DN")
	)
	(segment
		(start 152.85974 -235.31322)
		(end 152.46858 -235.31322)
		(width 0.13208)
		(layer "B.Cu")
		(net "CLK_100M_DB2000_CPU1_BCLK1_DN")
	)
	(segment
		(start 124.059696 -236.099604)
		(end 124.044964 -236.10824)
		(width 0.0889)
		(layer "B.Cu")
		(net "CLK_100M_DB2000_CPU1_BCLK1_DN")
	)
	(arc
		(start 129.309368 -236.10824)
		(mid 129.026666 -236.032498)
		(end 128.743964 -236.10824)
		(width 0.0889)
		(layer "B.Cu")
		(net "CLK_100M_DB2000_CPU1_BCLK1_DN")
	)
	(arc
		(start 128.369568 -236.10824)
		(mid 128.095339 -236.032315)
		(end 127.818896 -236.099604)
		(width 0.0889)
		(layer "B.Cu")
		(net "CLK_100M_DB2000_CPU1_BCLK1_DN")
	)
	(arc
		(start 131.563364 -236.10824)
		(mid 131.376166 -236.158383)
		(end 131.188968 -236.10824)
		(width 0.0889)
		(layer "B.Cu")
		(net "CLK_100M_DB2000_CPU1_BCLK1_DN")
	)
	(arc
		(start 134.008368 -236.10824)
		(mid 133.725666 -236.032498)
		(end 133.442964 -236.10824)
		(width 0.0889)
		(layer "B.Cu")
		(net "CLK_100M_DB2000_CPU1_BCLK1_DN")
	)
	(arc
		(start 124.984764 -236.10824)
		(mid 124.797566 -236.158383)
		(end 124.610368 -236.10824)
		(width 0.0889)
		(layer "B.Cu")
		(net "CLK_100M_DB2000_CPU1_BCLK1_DN")
	)
	(arc
		(start 128.743964 -236.10824)
		(mid 128.556766 -236.158383)
		(end 128.369568 -236.10824)
		(width 0.0889)
		(layer "B.Cu")
		(net "CLK_100M_DB2000_CPU1_BCLK1_DN")
	)
	(arc
		(start 132.128514 -236.10824)
		(mid 131.851955 -236.032531)
		(end 131.573778 -236.102144)
		(width 0.0889)
		(layer "B.Cu")
		(net "CLK_100M_DB2000_CPU1_BCLK1_DN")
	)
	(arc
		(start 130.249168 -236.10824)
		(mid 129.974939 -236.032315)
		(end 129.698496 -236.099604)
		(width 0.0889)
		(layer "B.Cu")
		(net "CLK_100M_DB2000_CPU1_BCLK1_DN")
	)
	(arc
		(start 122.165364 -236.10824)
		(mid 122.006876 -236.157173)
		(end 121.842784 -236.132878)
		(width 0.0889)
		(layer "B.Cu")
		(net "CLK_100M_DB2000_CPU1_BCLK1_DN")
	)
	(arc
		(start 133.068568 -236.10824)
		(mid 132.791755 -236.032404)
		(end 132.513324 -236.102144)
		(width 0.0889)
		(layer "B.Cu")
		(net "CLK_100M_DB2000_CPU1_BCLK1_DN")
	)
	(arc
		(start 124.610368 -236.10824)
		(mid 124.336139 -236.032315)
		(end 124.059696 -236.099604)
		(width 0.0889)
		(layer "B.Cu")
		(net "CLK_100M_DB2000_CPU1_BCLK1_DN")
	)
	(arc
		(start 135.40994 -236.917484)
		(mid 135.278528 -236.781152)
		(end 135.230616 -236.597952)
		(width 0.0889)
		(layer "B.Cu")
		(net "CLK_100M_DB2000_CPU1_BCLK1_DN")
	)
	(arc
		(start 134.382764 -236.10824)
		(mid 134.195566 -236.158383)
		(end 134.008368 -236.10824)
		(width 0.0889)
		(layer "B.Cu")
		(net "CLK_100M_DB2000_CPU1_BCLK1_DN")
	)
	(arc
		(start 125.92431 -236.10824)
		(mid 125.737112 -236.158383)
		(end 125.549914 -236.10824)
		(width 0.0889)
		(layer "B.Cu")
		(net "CLK_100M_DB2000_CPU1_BCLK1_DN")
	)
	(arc
		(start 129.683764 -236.10824)
		(mid 129.496566 -236.158383)
		(end 129.309368 -236.10824)
		(width 0.0889)
		(layer "B.Cu")
		(net "CLK_100M_DB2000_CPU1_BCLK1_DN")
	)
	(arc
		(start 123.670568 -236.10824)
		(mid 123.396339 -236.032315)
		(end 123.119896 -236.099604)
		(width 0.0889)
		(layer "B.Cu")
		(net "CLK_100M_DB2000_CPU1_BCLK1_DN")
	)
	(arc
		(start 131.188968 -236.10824)
		(mid 130.914739 -236.032315)
		(end 130.638296 -236.099604)
		(width 0.0889)
		(layer "B.Cu")
		(net "CLK_100M_DB2000_CPU1_BCLK1_DN")
	)
	(arc
		(start 127.804164 -236.10824)
		(mid 127.616966 -236.158383)
		(end 127.429768 -236.10824)
		(width 0.0889)
		(layer "B.Cu")
		(net "CLK_100M_DB2000_CPU1_BCLK1_DN")
	)
	(arc
		(start 126.489968 -236.10824)
		(mid 126.213155 -236.032404)
		(end 125.934724 -236.102144)
		(width 0.0889)
		(layer "B.Cu")
		(net "CLK_100M_DB2000_CPU1_BCLK1_DN")
	)
	(arc
		(start 135.230616 -236.57941)
		(mid 134.940138 -236.103691)
		(end 134.382764 -236.10824)
		(width 0.0889)
		(layer "B.Cu")
		(net "CLK_100M_DB2000_CPU1_BCLK1_DN")
	)
	(arc
		(start 122.730768 -236.10824)
		(mid 122.448066 -236.032498)
		(end 122.165364 -236.10824)
		(width 0.0889)
		(layer "B.Cu")
		(net "CLK_100M_DB2000_CPU1_BCLK1_DN")
	)
	(arc
		(start 127.429768 -236.10824)
		(mid 127.155539 -236.032315)
		(end 126.879096 -236.099604)
		(width 0.0889)
		(layer "B.Cu")
		(net "CLK_100M_DB2000_CPU1_BCLK1_DN")
	)
	(arc
		(start 123.105164 -236.10824)
		(mid 122.917966 -236.158383)
		(end 122.730768 -236.10824)
		(width 0.0889)
		(layer "B.Cu")
		(net "CLK_100M_DB2000_CPU1_BCLK1_DN")
	)
	(arc
		(start 133.442964 -236.10824)
		(mid 133.255766 -236.158383)
		(end 133.068568 -236.10824)
		(width 0.0889)
		(layer "B.Cu")
		(net "CLK_100M_DB2000_CPU1_BCLK1_DN")
	)
	(arc
		(start 124.044964 -236.10824)
		(mid 123.857766 -236.158383)
		(end 123.670568 -236.10824)
		(width 0.0889)
		(layer "B.Cu")
		(net "CLK_100M_DB2000_CPU1_BCLK1_DN")
	)
	(arc
		(start 125.549914 -236.10824)
		(mid 125.273355 -236.032531)
		(end 124.995178 -236.102144)
		(width 0.0889)
		(layer "B.Cu")
		(net "CLK_100M_DB2000_CPU1_BCLK1_DN")
	)
	(arc
		(start 130.623564 -236.10824)
		(mid 130.436366 -236.158383)
		(end 130.249168 -236.10824)
		(width 0.0889)
		(layer "B.Cu")
		(net "CLK_100M_DB2000_CPU1_BCLK1_DN")
	)
	(arc
		(start 126.864364 -236.10824)
		(mid 126.677166 -236.158383)
		(end 126.489968 -236.10824)
		(width 0.0889)
		(layer "B.Cu")
		(net "CLK_100M_DB2000_CPU1_BCLK1_DN")
	)
	(arc
		(start 135.916924 -237.056676)
		(mid 135.658449 -237.022433)
		(end 135.417814 -236.922056)
		(width 0.0889)
		(layer "B.Cu")
		(net "CLK_100M_DB2000_CPU1_BCLK1_DN")
	)
	(arc
		(start 132.50291 -236.10824)
		(mid 132.315712 -236.158383)
		(end 132.128514 -236.10824)
		(width 0.0889)
		(layer "B.Cu")
		(net "CLK_100M_DB2000_CPU1_BCLK1_DN")
	)
	(segment
		(start 233.88574 -133.713982)
		(end 234.63504 -131.903978)
		(width 0.13208)
		(layer "F.Cu")
		(net "CLK_100M_DB2000_CPU1_BCLK0_DP")
	)
	(segment
		(start 234.63758 -129.628392)
		(end 234.74807 -129.517902)
		(width 0.13208)
		(layer "F.Cu")
		(net "CLK_100M_DB2000_CPU1_BCLK0_DP")
	)
	(segment
		(start 234.63504 -129.645918)
		(end 234.63758 -129.643378)
		(width 0.13208)
		(layer "F.Cu")
		(net "CLK_100M_DB2000_CPU1_BCLK0_DP")
	)
	(segment
		(start 234.63758 -129.643378)
		(end 234.63758 -129.628392)
		(width 0.13208)
		(layer "F.Cu")
		(net "CLK_100M_DB2000_CPU1_BCLK0_DP")
	)
	(segment
		(start 229.47884 -134.310628)
		(end 229.63632 -134.153148)
		(width 0.13208)
		(layer "F.Cu")
		(net "CLK_100M_DB2000_CPU1_BCLK0_DP")
	)
	(segment
		(start 102.242366 -237.947454)
		(end 102.242366 -237.411514)
		(width 0.13208)
		(layer "F.Cu")
		(net "CLK_100M_DB2000_CPU1_BCLK0_DP")
	)
	(segment
		(start 102.242112 -237.947454)
		(end 102.242366 -237.947454)
		(width 0.13208)
		(layer "F.Cu")
		(net "CLK_100M_DB2000_CPU1_BCLK0_DP")
	)
	(segment
		(start 234.63504 -131.903978)
		(end 234.63504 -129.645918)
		(width 0.13208)
		(layer "F.Cu")
		(net "CLK_100M_DB2000_CPU1_BCLK0_DP")
	)
	(segment
		(start 233.228642 -134.153148)
		(end 233.88574 -133.713982)
		(width 0.13208)
		(layer "F.Cu")
		(net "CLK_100M_DB2000_CPU1_BCLK0_DP")
	)
	(segment
		(start 229.63632 -134.153148)
		(end 233.228642 -134.153148)
		(width 0.13208)
		(layer "F.Cu")
		(net "CLK_100M_DB2000_CPU1_BCLK0_DP")
	)
	(segment
		(start 229.77602 -135.029448)
		(end 229.47884 -134.732268)
		(width 0.13208)
		(layer "F.Cu")
		(net "CLK_100M_DB2000_CPU1_BCLK0_DP")
	)
	(segment
		(start 229.47884 -134.732268)
		(end 229.47884 -134.310628)
		(width 0.13208)
		(layer "F.Cu")
		(net "CLK_100M_DB2000_CPU1_BCLK0_DP")
	)
	(via
		(at 229.77602 -135.029448)
		(size 0.508)
		(drill 0.254)
		(layers "F.Cu" "B.Cu")
		(net "CLK_100M_DB2000_CPU1_BCLK0_DP")
	)
	(via
		(at 102.242366 -237.411514)
		(size 0.4572)
		(drill 0.2032)
		(layers "F.Cu" "B.Cu")
		(net "CLK_100M_DB2000_CPU1_BCLK0_DP")
	)
	(segment
		(start 98.2853 -237.729776)
		(end 98.295714 -237.735872)
		(width 0.0889)
		(layer "B.Cu")
		(net "CLK_100M_DB2000_CPU1_BCLK0_DP")
	)
	(segment
		(start 92.09151 -237.735872)
		(end 92.101924 -237.729776)
		(width 0.0889)
		(layer "B.Cu")
		(net "CLK_100M_DB2000_CPU1_BCLK0_DP")
	)
	(segment
		(start 100.942902 -236.970824)
		(end 101.019864 -236.922056)
		(width 0.0889)
		(layer "B.Cu")
		(net "CLK_100M_DB2000_CPU1_BCLK0_DP")
	)
	(segment
		(start 101.5746 -236.91596)
		(end 101.588062 -236.923834)
		(width 0.0889)
		(layer "B.Cu")
		(net "CLK_100M_DB2000_CPU1_BCLK0_DP")
	)
	(segment
		(start 61.666374 -203.00188)
		(end 61.45022 -203.522834)
		(width 0.13208)
		(layer "B.Cu")
		(net "CLK_100M_DB2000_CPU1_BCLK0_DP")
	)
	(segment
		(start 62.762638 -234.153456)
		(end 66.176652 -235.978446)
		(width 0.13208)
		(layer "B.Cu")
		(net "CLK_100M_DB2000_CPU1_BCLK0_DP")
	)
	(segment
		(start 224.911158 -134.53999)
		(end 185.429652 -142.392908)
		(width 0.13208)
		(layer "B.Cu")
		(net "CLK_100M_DB2000_CPU1_BCLK0_DP")
	)
	(segment
		(start 78.534514 -239.402112)
		(end 83.551522 -239.402112)
		(width 0.13208)
		(layer "B.Cu")
		(net "CLK_100M_DB2000_CPU1_BCLK0_DP")
	)
	(segment
		(start 67.07124 -192.647316)
		(end 67.07124 -198.223378)
		(width 0.13208)
		(layer "B.Cu")
		(net "CLK_100M_DB2000_CPU1_BCLK0_DP")
	)
	(segment
		(start 72.695562 -176.834292)
		(end 72.05599 -177.791618)
		(width 0.13208)
		(layer "B.Cu")
		(net "CLK_100M_DB2000_CPU1_BCLK0_DP")
	)
	(segment
		(start 90.212164 -237.735872)
		(end 90.226896 -237.727236)
		(width 0.0889)
		(layer "B.Cu")
		(net "CLK_100M_DB2000_CPU1_BCLK0_DP")
	)
	(segment
		(start 101.588062 -236.923834)
		(end 101.635306 -236.951774)
		(width 0.0889)
		(layer "B.Cu")
		(net "CLK_100M_DB2000_CPU1_BCLK0_DP")
	)
	(segment
		(start 94.911164 -237.735872)
		(end 94.925896 -237.727236)
		(width 0.0889)
		(layer "B.Cu")
		(net "CLK_100M_DB2000_CPU1_BCLK0_DP")
	)
	(segment
		(start 100.737416 -237.401354)
		(end 100.738686 -237.336584)
		(width 0.0889)
		(layer "B.Cu")
		(net "CLK_100M_DB2000_CPU1_BCLK0_DP")
	)
	(segment
		(start 95.850964 -237.735872)
		(end 95.865696 -237.727236)
		(width 0.0889)
		(layer "B.Cu")
		(net "CLK_100M_DB2000_CPU1_BCLK0_DP")
	)
	(segment
		(start 229.77602 -135.029448)
		(end 229.47376 -135.331708)
		(width 0.13208)
		(layer "B.Cu")
		(net "CLK_100M_DB2000_CPU1_BCLK0_DP")
	)
	(segment
		(start 71.702168 -178.958748)
		(end 70.503288 -180.157628)
		(width 0.13208)
		(layer "B.Cu")
		(net "CLK_100M_DB2000_CPU1_BCLK0_DP")
	)
	(segment
		(start 98.678238 -237.731046)
		(end 98.680524 -237.729776)
		(width 0.0889)
		(layer "B.Cu")
		(net "CLK_100M_DB2000_CPU1_BCLK0_DP")
	)
	(segment
		(start 74.605896 -176.042828)
		(end 72.695562 -176.834292)
		(width 0.13208)
		(layer "B.Cu")
		(net "CLK_100M_DB2000_CPU1_BCLK0_DP")
	)
	(segment
		(start 185.429652 -142.392908)
		(end 108.10875 -142.392908)
		(width 0.13208)
		(layer "B.Cu")
		(net "CLK_100M_DB2000_CPU1_BCLK0_DP")
	)
	(segment
		(start 227.5586 -134.88289)
		(end 227.161598 -134.485888)
		(width 0.13208)
		(layer "B.Cu")
		(net "CLK_100M_DB2000_CPU1_BCLK0_DP")
	)
	(segment
		(start 66.89344 -192.219326)
		(end 67.07124 -192.647316)
		(width 0.13208)
		(layer "B.Cu")
		(net "CLK_100M_DB2000_CPU1_BCLK0_DP")
	)
	(segment
		(start 76.32192 -175.21555)
		(end 75.494642 -176.042828)
		(width 0.13208)
		(layer "B.Cu")
		(net "CLK_100M_DB2000_CPU1_BCLK0_DP")
	)
	(segment
		(start 61.7982 -233.509312)
		(end 62.762638 -234.153456)
		(width 0.13208)
		(layer "B.Cu")
		(net "CLK_100M_DB2000_CPU1_BCLK0_DP")
	)
	(segment
		(start 107.265216 -142.742412)
		(end 106.421936 -143.091662)
		(width 0.13208)
		(layer "B.Cu")
		(net "CLK_100M_DB2000_CPU1_BCLK0_DP")
	)
	(segment
		(start 70.503288 -180.157628)
		(end 67.344798 -180.157628)
		(width 0.13208)
		(layer "B.Cu")
		(net "CLK_100M_DB2000_CPU1_BCLK0_DP")
	)
	(segment
		(start 88.332564 -237.735872)
		(end 88.347296 -237.727236)
		(width 0.0889)
		(layer "B.Cu")
		(net "CLK_100M_DB2000_CPU1_BCLK0_DP")
	)
	(segment
		(start 101.853238 -237.2741)
		(end 101.861112 -237.3249)
		(width 0.0889)
		(layer "B.Cu")
		(net "CLK_100M_DB2000_CPU1_BCLK0_DP")
	)
	(segment
		(start 85.66531 -239.435132)
		(end 85.665564 -239.435386)
		(width 0.0889)
		(layer "B.Cu")
		(net "CLK_100M_DB2000_CPU1_BCLK0_DP")
	)
	(segment
		(start 66.176652 -235.978446)
		(end 76.017374 -238.964978)
		(width 0.13208)
		(layer "B.Cu")
		(net "CLK_100M_DB2000_CPU1_BCLK0_DP")
	)
	(segment
		(start 227.161598 -134.485888)
		(end 225.18243 -134.485888)
		(width 0.13208)
		(layer "B.Cu")
		(net "CLK_100M_DB2000_CPU1_BCLK0_DP")
	)
	(segment
		(start 228.915722 -136.291828)
		(end 228.167438 -136.291828)
		(width 0.13208)
		(layer "B.Cu")
		(net "CLK_100M_DB2000_CPU1_BCLK0_DP")
	)
	(segment
		(start 67.07124 -198.223378)
		(end 66.764916 -198.964042)
		(width 0.13208)
		(layer "B.Cu")
		(net "CLK_100M_DB2000_CPU1_BCLK0_DP")
	)
	(segment
		(start 76.32192 -173.191932)
		(end 76.32192 -175.21555)
		(width 0.13208)
		(layer "B.Cu")
		(net "CLK_100M_DB2000_CPU1_BCLK0_DP")
	)
	(segment
		(start 64.336676 -201.392282)
		(end 62.525656 -202.142598)
		(width 0.13208)
		(layer "B.Cu")
		(net "CLK_100M_DB2000_CPU1_BCLK0_DP")
	)
	(segment
		(start 65.689226 -190.11646)
		(end 66.016886 -190.907416)
		(width 0.13208)
		(layer "B.Cu")
		(net "CLK_100M_DB2000_CPU1_BCLK0_DP")
	)
	(segment
		(start 101.863906 -237.345728)
		(end 101.929692 -237.411514)
		(width 0.0889)
		(layer "B.Cu")
		(net "CLK_100M_DB2000_CPU1_BCLK0_DP")
	)
	(segment
		(start 229.47376 -135.331708)
		(end 229.47376 -135.73379)
		(width 0.13208)
		(layer "B.Cu")
		(net "CLK_100M_DB2000_CPU1_BCLK0_DP")
	)
	(segment
		(start 61.45022 -232.917492)
		(end 61.622686 -233.333544)
		(width 0.13208)
		(layer "B.Cu")
		(net "CLK_100M_DB2000_CPU1_BCLK0_DP")
	)
	(segment
		(start 76.017374 -238.964978)
		(end 78.534514 -239.402112)
		(width 0.13208)
		(layer "B.Cu")
		(net "CLK_100M_DB2000_CPU1_BCLK0_DP")
	)
	(segment
		(start 64.94018 -186.347608)
		(end 65.689226 -190.11646)
		(width 0.13208)
		(layer "B.Cu")
		(net "CLK_100M_DB2000_CPU1_BCLK0_DP")
	)
	(segment
		(start 99.610164 -237.735872)
		(end 99.624896 -237.727236)
		(width 0.0889)
		(layer "B.Cu")
		(net "CLK_100M_DB2000_CPU1_BCLK0_DP")
	)
	(segment
		(start 75.494642 -176.042828)
		(end 74.605896 -176.042828)
		(width 0.13208)
		(layer "B.Cu")
		(net "CLK_100M_DB2000_CPU1_BCLK0_DP")
	)
	(segment
		(start 66.764916 -198.964042)
		(end 64.336676 -201.392282)
		(width 0.13208)
		(layer "B.Cu")
		(net "CLK_100M_DB2000_CPU1_BCLK0_DP")
	)
	(segment
		(start 83.57362 -239.399572)
		(end 83.60918 -239.435132)
		(width 0.0889)
		(layer "B.Cu")
		(net "CLK_100M_DB2000_CPU1_BCLK0_DP")
	)
	(segment
		(start 229.47376 -135.73379)
		(end 228.915722 -136.291828)
		(width 0.13208)
		(layer "B.Cu")
		(net "CLK_100M_DB2000_CPU1_BCLK0_DP")
	)
	(segment
		(start 98.67011 -237.735872)
		(end 98.678238 -237.731046)
		(width 0.0889)
		(layer "B.Cu")
		(net "CLK_100M_DB2000_CPU1_BCLK0_DP")
	)
	(segment
		(start 66.016886 -190.907416)
		(end 66.89344 -192.219326)
		(width 0.13208)
		(layer "B.Cu")
		(net "CLK_100M_DB2000_CPU1_BCLK0_DP")
	)
	(segment
		(start 89.272364 -237.735872)
		(end 89.287096 -237.727236)
		(width 0.0889)
		(layer "B.Cu")
		(net "CLK_100M_DB2000_CPU1_BCLK0_DP")
	)
	(segment
		(start 67.344798 -180.157628)
		(end 64.94018 -182.562246)
		(width 0.13208)
		(layer "B.Cu")
		(net "CLK_100M_DB2000_CPU1_BCLK0_DP")
	)
	(segment
		(start 227.5586 -135.68299)
		(end 227.5586 -134.88289)
		(width 0.13208)
		(layer "B.Cu")
		(net "CLK_100M_DB2000_CPU1_BCLK0_DP")
	)
	(segment
		(start 61.45022 -203.522834)
		(end 61.45022 -232.917492)
		(width 0.13208)
		(layer "B.Cu")
		(net "CLK_100M_DB2000_CPU1_BCLK0_DP")
	)
	(segment
		(start 106.421936 -143.091662)
		(end 76.32192 -173.191932)
		(width 0.13208)
		(layer "B.Cu")
		(net "CLK_100M_DB2000_CPU1_BCLK0_DP")
	)
	(segment
		(start 93.031564 -237.735872)
		(end 93.046296 -237.727236)
		(width 0.0889)
		(layer "B.Cu")
		(net "CLK_100M_DB2000_CPU1_BCLK0_DP")
	)
	(segment
		(start 72.05599 -177.791618)
		(end 71.702168 -178.958748)
		(width 0.13208)
		(layer "B.Cu")
		(net "CLK_100M_DB2000_CPU1_BCLK0_DP")
	)
	(segment
		(start 83.60918 -239.435132)
		(end 85.66531 -239.435132)
		(width 0.0889)
		(layer "B.Cu")
		(net "CLK_100M_DB2000_CPU1_BCLK0_DP")
	)
	(segment
		(start 96.790764 -237.735872)
		(end 96.805496 -237.727236)
		(width 0.0889)
		(layer "B.Cu")
		(net "CLK_100M_DB2000_CPU1_BCLK0_DP")
	)
	(segment
		(start 100.737416 -237.411514)
		(end 100.737416 -237.401354)
		(width 0.0889)
		(layer "B.Cu")
		(net "CLK_100M_DB2000_CPU1_BCLK0_DP")
	)
	(segment
		(start 93.971364 -237.735872)
		(end 93.986096 -237.727236)
		(width 0.0889)
		(layer "B.Cu")
		(net "CLK_100M_DB2000_CPU1_BCLK0_DP")
	)
	(segment
		(start 83.554062 -239.399572)
		(end 83.57362 -239.399572)
		(width 0.0889)
		(layer "B.Cu")
		(net "CLK_100M_DB2000_CPU1_BCLK0_DP")
	)
	(segment
		(start 91.7067 -237.729776)
		(end 91.717114 -237.735872)
		(width 0.0889)
		(layer "B.Cu")
		(net "CLK_100M_DB2000_CPU1_BCLK0_DP")
	)
	(segment
		(start 64.94018 -182.562246)
		(end 64.94018 -186.347608)
		(width 0.13208)
		(layer "B.Cu")
		(net "CLK_100M_DB2000_CPU1_BCLK0_DP")
	)
	(segment
		(start 228.167438 -136.291828)
		(end 227.5586 -135.68299)
		(width 0.13208)
		(layer "B.Cu")
		(net "CLK_100M_DB2000_CPU1_BCLK0_DP")
	)
	(segment
		(start 225.18243 -134.485888)
		(end 224.911158 -134.53999)
		(width 0.13208)
		(layer "B.Cu")
		(net "CLK_100M_DB2000_CPU1_BCLK0_DP")
	)
	(segment
		(start 83.551522 -239.402112)
		(end 83.554062 -239.399572)
		(width 0.0889)
		(layer "B.Cu")
		(net "CLK_100M_DB2000_CPU1_BCLK0_DP")
	)
	(segment
		(start 61.622686 -233.333544)
		(end 61.7982 -233.509312)
		(width 0.13208)
		(layer "B.Cu")
		(net "CLK_100M_DB2000_CPU1_BCLK0_DP")
	)
	(segment
		(start 101.929692 -237.411514)
		(end 102.242366 -237.411514)
		(width 0.0889)
		(layer "B.Cu")
		(net "CLK_100M_DB2000_CPU1_BCLK0_DP")
	)
	(segment
		(start 108.10875 -142.392908)
		(end 107.265216 -142.742412)
		(width 0.13208)
		(layer "B.Cu")
		(net "CLK_100M_DB2000_CPU1_BCLK0_DP")
	)
	(segment
		(start 85.665564 -239.435386)
		(end 87.276178 -237.824772)
		(width 0.0889)
		(layer "B.Cu")
		(net "CLK_100M_DB2000_CPU1_BCLK0_DP")
	)
	(segment
		(start 62.525656 -202.142598)
		(end 61.666374 -203.00188)
		(width 0.13208)
		(layer "B.Cu")
		(net "CLK_100M_DB2000_CPU1_BCLK0_DP")
	)
	(arc
		(start 91.151964 -237.735872)
		(mid 91.428523 -237.660163)
		(end 91.7067 -237.729776)
		(width 0.0889)
		(layer "B.Cu")
		(net "CLK_100M_DB2000_CPU1_BCLK0_DP")
	)
	(arc
		(start 96.416368 -237.735872)
		(mid 96.603566 -237.786015)
		(end 96.790764 -237.735872)
		(width 0.0889)
		(layer "B.Cu")
		(net "CLK_100M_DB2000_CPU1_BCLK0_DP")
	)
	(arc
		(start 98.295714 -237.735872)
		(mid 98.482912 -237.786015)
		(end 98.67011 -237.735872)
		(width 0.0889)
		(layer "B.Cu")
		(net "CLK_100M_DB2000_CPU1_BCLK0_DP")
	)
	(arc
		(start 87.4014 -237.730792)
		(mid 87.680442 -237.660107)
		(end 87.958168 -237.735872)
		(width 0.0889)
		(layer "B.Cu")
		(net "CLK_100M_DB2000_CPU1_BCLK0_DP")
	)
	(arc
		(start 95.476568 -237.735872)
		(mid 95.663766 -237.786015)
		(end 95.850964 -237.735872)
		(width 0.0889)
		(layer "B.Cu")
		(net "CLK_100M_DB2000_CPU1_BCLK0_DP")
	)
	(arc
		(start 100.175568 -237.735872)
		(mid 100.550043 -237.735826)
		(end 100.737416 -237.411514)
		(width 0.0889)
		(layer "B.Cu")
		(net "CLK_100M_DB2000_CPU1_BCLK0_DP")
	)
	(arc
		(start 94.536768 -237.735872)
		(mid 94.723966 -237.786015)
		(end 94.911164 -237.735872)
		(width 0.0889)
		(layer "B.Cu")
		(net "CLK_100M_DB2000_CPU1_BCLK0_DP")
	)
	(arc
		(start 94.925896 -237.727236)
		(mid 95.202337 -237.66007)
		(end 95.476568 -237.735872)
		(width 0.0889)
		(layer "B.Cu")
		(net "CLK_100M_DB2000_CPU1_BCLK0_DP")
	)
	(arc
		(start 97.730564 -237.735872)
		(mid 98.007123 -237.660163)
		(end 98.2853 -237.729776)
		(width 0.0889)
		(layer "B.Cu")
		(net "CLK_100M_DB2000_CPU1_BCLK0_DP")
	)
	(arc
		(start 99.235768 -237.735872)
		(mid 99.422966 -237.786015)
		(end 99.610164 -237.735872)
		(width 0.0889)
		(layer "B.Cu")
		(net "CLK_100M_DB2000_CPU1_BCLK0_DP")
	)
	(arc
		(start 89.287096 -237.727236)
		(mid 89.563537 -237.66007)
		(end 89.837768 -237.735872)
		(width 0.0889)
		(layer "B.Cu")
		(net "CLK_100M_DB2000_CPU1_BCLK0_DP")
	)
	(arc
		(start 93.986096 -237.727236)
		(mid 94.262537 -237.66007)
		(end 94.536768 -237.735872)
		(width 0.0889)
		(layer "B.Cu")
		(net "CLK_100M_DB2000_CPU1_BCLK0_DP")
	)
	(arc
		(start 92.657168 -237.735872)
		(mid 92.844366 -237.786015)
		(end 93.031564 -237.735872)
		(width 0.0889)
		(layer "B.Cu")
		(net "CLK_100M_DB2000_CPU1_BCLK0_DP")
	)
	(arc
		(start 97.356168 -237.735872)
		(mid 97.543366 -237.786015)
		(end 97.730564 -237.735872)
		(width 0.0889)
		(layer "B.Cu")
		(net "CLK_100M_DB2000_CPU1_BCLK0_DP")
	)
	(arc
		(start 92.101924 -237.729776)
		(mid 92.380356 -237.659962)
		(end 92.657168 -237.735872)
		(width 0.0889)
		(layer "B.Cu")
		(net "CLK_100M_DB2000_CPU1_BCLK0_DP")
	)
	(arc
		(start 91.717114 -237.735872)
		(mid 91.904312 -237.786015)
		(end 92.09151 -237.735872)
		(width 0.0889)
		(layer "B.Cu")
		(net "CLK_100M_DB2000_CPU1_BCLK0_DP")
	)
	(arc
		(start 96.805496 -237.727236)
		(mid 97.081937 -237.66007)
		(end 97.356168 -237.735872)
		(width 0.0889)
		(layer "B.Cu")
		(net "CLK_100M_DB2000_CPU1_BCLK0_DP")
	)
	(arc
		(start 89.837768 -237.735872)
		(mid 90.024966 -237.786015)
		(end 90.212164 -237.735872)
		(width 0.0889)
		(layer "B.Cu")
		(net "CLK_100M_DB2000_CPU1_BCLK0_DP")
	)
	(arc
		(start 100.738686 -237.336584)
		(mid 100.794907 -237.128068)
		(end 100.942902 -236.970824)
		(width 0.0889)
		(layer "B.Cu")
		(net "CLK_100M_DB2000_CPU1_BCLK0_DP")
	)
	(arc
		(start 87.276178 -237.824772)
		(mid 87.335527 -237.773437)
		(end 87.4014 -237.730792)
		(width 0.0889)
		(layer "B.Cu")
		(net "CLK_100M_DB2000_CPU1_BCLK0_DP")
	)
	(arc
		(start 101.861112 -237.3249)
		(mid 101.862607 -237.335301)
		(end 101.863906 -237.345728)
		(width 0.0889)
		(layer "B.Cu")
		(net "CLK_100M_DB2000_CPU1_BCLK0_DP")
	)
	(arc
		(start 101.635306 -236.951774)
		(mid 101.780312 -237.088556)
		(end 101.853238 -237.2741)
		(width 0.0889)
		(layer "B.Cu")
		(net "CLK_100M_DB2000_CPU1_BCLK0_DP")
	)
	(arc
		(start 98.680524 -237.729776)
		(mid 98.958956 -237.659962)
		(end 99.235768 -237.735872)
		(width 0.0889)
		(layer "B.Cu")
		(net "CLK_100M_DB2000_CPU1_BCLK0_DP")
	)
	(arc
		(start 99.624896 -237.727236)
		(mid 99.901337 -237.66007)
		(end 100.175568 -237.735872)
		(width 0.0889)
		(layer "B.Cu")
		(net "CLK_100M_DB2000_CPU1_BCLK0_DP")
	)
	(arc
		(start 95.865696 -237.727236)
		(mid 96.142137 -237.66007)
		(end 96.416368 -237.735872)
		(width 0.0889)
		(layer "B.Cu")
		(net "CLK_100M_DB2000_CPU1_BCLK0_DP")
	)
	(arc
		(start 87.958168 -237.735872)
		(mid 88.145366 -237.786015)
		(end 88.332564 -237.735872)
		(width 0.0889)
		(layer "B.Cu")
		(net "CLK_100M_DB2000_CPU1_BCLK0_DP")
	)
	(arc
		(start 88.897968 -237.735872)
		(mid 89.085166 -237.786015)
		(end 89.272364 -237.735872)
		(width 0.0889)
		(layer "B.Cu")
		(net "CLK_100M_DB2000_CPU1_BCLK0_DP")
	)
	(arc
		(start 88.347296 -237.727236)
		(mid 88.623737 -237.66007)
		(end 88.897968 -237.735872)
		(width 0.0889)
		(layer "B.Cu")
		(net "CLK_100M_DB2000_CPU1_BCLK0_DP")
	)
	(arc
		(start 90.226896 -237.727236)
		(mid 90.503337 -237.66007)
		(end 90.777568 -237.735872)
		(width 0.0889)
		(layer "B.Cu")
		(net "CLK_100M_DB2000_CPU1_BCLK0_DP")
	)
	(arc
		(start 101.019864 -236.922056)
		(mid 101.296423 -236.846313)
		(end 101.5746 -236.91596)
		(width 0.0889)
		(layer "B.Cu")
		(net "CLK_100M_DB2000_CPU1_BCLK0_DP")
	)
	(arc
		(start 93.046296 -237.727236)
		(mid 93.322737 -237.66007)
		(end 93.596968 -237.735872)
		(width 0.0889)
		(layer "B.Cu")
		(net "CLK_100M_DB2000_CPU1_BCLK0_DP")
	)
	(arc
		(start 93.596968 -237.735872)
		(mid 93.784166 -237.786015)
		(end 93.971364 -237.735872)
		(width 0.0889)
		(layer "B.Cu")
		(net "CLK_100M_DB2000_CPU1_BCLK0_DP")
	)
	(arc
		(start 90.777568 -237.735872)
		(mid 90.964766 -237.786015)
		(end 91.151964 -237.735872)
		(width 0.0889)
		(layer "B.Cu")
		(net "CLK_100M_DB2000_CPU1_BCLK0_DP")
	)
	(segment
		(start 229.528878 -133.894068)
		(end 233.149902 -133.894068)
		(width 0.13208)
		(layer "F.Cu")
		(net "CLK_100M_DB2000_CPU1_BCLK0_DN")
	)
	(segment
		(start 233.67619 -133.542024)
		(end 234.37596 -131.852416)
		(width 0.13208)
		(layer "F.Cu")
		(net "CLK_100M_DB2000_CPU1_BCLK0_DN")
	)
	(segment
		(start 101.302566 -237.947454)
		(end 101.302566 -237.411514)
		(width 0.13208)
		(layer "F.Cu")
		(net "CLK_100M_DB2000_CPU1_BCLK0_DN")
	)
	(segment
		(start 101.302312 -237.947454)
		(end 101.302566 -237.947454)
		(width 0.13208)
		(layer "F.Cu")
		(net "CLK_100M_DB2000_CPU1_BCLK0_DN")
	)
	(segment
		(start 229.21976 -134.722108)
		(end 229.21976 -134.203186)
		(width 0.13208)
		(layer "F.Cu")
		(net "CLK_100M_DB2000_CPU1_BCLK0_DN")
	)
	(segment
		(start 234.37596 -129.645918)
		(end 234.247944 -129.517902)
		(width 0.13208)
		(layer "F.Cu")
		(net "CLK_100M_DB2000_CPU1_BCLK0_DN")
	)
	(segment
		(start 233.149902 -133.894068)
		(end 233.67619 -133.542024)
		(width 0.13208)
		(layer "F.Cu")
		(net "CLK_100M_DB2000_CPU1_BCLK0_DN")
	)
	(segment
		(start 234.37596 -131.852416)
		(end 234.37596 -129.645918)
		(width 0.13208)
		(layer "F.Cu")
		(net "CLK_100M_DB2000_CPU1_BCLK0_DN")
	)
	(segment
		(start 228.91242 -135.029448)
		(end 229.21976 -134.722108)
		(width 0.13208)
		(layer "F.Cu")
		(net "CLK_100M_DB2000_CPU1_BCLK0_DN")
	)
	(segment
		(start 229.21976 -134.203186)
		(end 229.528878 -133.894068)
		(width 0.13208)
		(layer "F.Cu")
		(net "CLK_100M_DB2000_CPU1_BCLK0_DN")
	)
	(via
		(at 101.302566 -237.411514)
		(size 0.4572)
		(drill 0.2032)
		(layers "F.Cu" "B.Cu")
		(net "CLK_100M_DB2000_CPU1_BCLK0_DN")
	)
	(via
		(at 228.91242 -135.029448)
		(size 0.508)
		(drill 0.254)
		(layers "F.Cu" "B.Cu")
		(net "CLK_100M_DB2000_CPU1_BCLK0_DN")
	)
	(segment
		(start 106.275124 -142.871952)
		(end 76.06284 -173.08449)
		(width 0.13208)
		(layer "B.Cu")
		(net "CLK_100M_DB2000_CPU1_BCLK0_DN")
	)
	(segment
		(start 61.632846 -233.710734)
		(end 62.629288 -234.37596)
		(width 0.13208)
		(layer "B.Cu")
		(net "CLK_100M_DB2000_CPU1_BCLK0_DN")
	)
	(segment
		(start 61.402976 -233.480356)
		(end 61.632846 -233.710734)
		(width 0.13208)
		(layer "B.Cu")
		(net "CLK_100M_DB2000_CPU1_BCLK0_DN")
	)
	(segment
		(start 61.446664 -202.854814)
		(end 61.19114 -203.471018)
		(width 0.13208)
		(layer "B.Cu")
		(net "CLK_100M_DB2000_CPU1_BCLK0_DN")
	)
	(segment
		(start 71.819008 -177.679604)
		(end 71.47306 -178.821334)
		(width 0.13208)
		(layer "B.Cu")
		(net "CLK_100M_DB2000_CPU1_BCLK0_DN")
	)
	(segment
		(start 101.665024 -237.30331)
		(end 101.672898 -237.353856)
		(width 0.0889)
		(layer "B.Cu")
		(net "CLK_100M_DB2000_CPU1_BCLK0_DN")
	)
	(segment
		(start 76.06284 -175.108108)
		(end 75.3872 -175.783748)
		(width 0.13208)
		(layer "B.Cu")
		(net "CLK_100M_DB2000_CPU1_BCLK0_DN")
	)
	(segment
		(start 66.663062 -192.341246)
		(end 66.66357 -192.342262)
		(width 0.13208)
		(layer "B.Cu")
		(net "CLK_100M_DB2000_CPU1_BCLK0_DN")
	)
	(segment
		(start 66.81216 -192.700402)
		(end 66.81216 -198.171816)
		(width 0.13208)
		(layer "B.Cu")
		(net "CLK_100M_DB2000_CPU1_BCLK0_DN")
	)
	(segment
		(start 83.551522 -239.661192)
		(end 83.57362 -239.661192)
		(width 0.0889)
		(layer "B.Cu")
		(net "CLK_100M_DB2000_CPU1_BCLK0_DN")
	)
	(segment
		(start 74.554334 -175.783748)
		(end 72.523604 -176.624742)
		(width 0.13208)
		(layer "B.Cu")
		(net "CLK_100M_DB2000_CPU1_BCLK0_DN")
	)
	(segment
		(start 96.871282 -237.909862)
		(end 96.886014 -237.901226)
		(width 0.0889)
		(layer "B.Cu")
		(net "CLK_100M_DB2000_CPU1_BCLK0_DN")
	)
	(segment
		(start 66.545206 -198.81723)
		(end 64.189864 -201.172572)
		(width 0.13208)
		(layer "B.Cu")
		(net "CLK_100M_DB2000_CPU1_BCLK0_DN")
	)
	(segment
		(start 93.112082 -237.909862)
		(end 93.126814 -237.901226)
		(width 0.0889)
		(layer "B.Cu")
		(net "CLK_100M_DB2000_CPU1_BCLK0_DN")
	)
	(segment
		(start 227.81768 -135.575548)
		(end 227.81768 -134.775448)
		(width 0.13208)
		(layer "B.Cu")
		(net "CLK_100M_DB2000_CPU1_BCLK0_DN")
	)
	(segment
		(start 65.439798 -190.192152)
		(end 65.787016 -191.030352)
		(width 0.13208)
		(layer "B.Cu")
		(net "CLK_100M_DB2000_CPU1_BCLK0_DN")
	)
	(segment
		(start 62.629288 -234.37596)
		(end 66.07683 -236.219238)
		(width 0.13208)
		(layer "B.Cu")
		(net "CLK_100M_DB2000_CPU1_BCLK0_DN")
	)
	(segment
		(start 85.744812 -239.625378)
		(end 87.410036 -237.960154)
		(width 0.0889)
		(layer "B.Cu")
		(net "CLK_100M_DB2000_CPU1_BCLK0_DN")
	)
	(segment
		(start 76.06284 -173.08449)
		(end 76.06284 -175.108108)
		(width 0.13208)
		(layer "B.Cu")
		(net "CLK_100M_DB2000_CPU1_BCLK0_DN")
	)
	(segment
		(start 83.609434 -239.625378)
		(end 85.744812 -239.625378)
		(width 0.0889)
		(layer "B.Cu")
		(net "CLK_100M_DB2000_CPU1_BCLK0_DN")
	)
	(segment
		(start 228.91242 -135.029448)
		(end 229.21468 -135.331708)
		(width 0.13208)
		(layer "B.Cu")
		(net "CLK_100M_DB2000_CPU1_BCLK0_DN")
	)
	(segment
		(start 64.189864 -201.172572)
		(end 62.378844 -201.922888)
		(width 0.13208)
		(layer "B.Cu")
		(net "CLK_100M_DB2000_CPU1_BCLK0_DN")
	)
	(segment
		(start 101.491288 -237.087918)
		(end 101.538278 -237.115604)
		(width 0.0889)
		(layer "B.Cu")
		(net "CLK_100M_DB2000_CPU1_BCLK0_DN")
	)
	(segment
		(start 229.21468 -135.331708)
		(end 229.21468 -135.626348)
		(width 0.13208)
		(layer "B.Cu")
		(net "CLK_100M_DB2000_CPU1_BCLK0_DN")
	)
	(segment
		(start 228.80828 -136.032748)
		(end 228.27488 -136.032748)
		(width 0.13208)
		(layer "B.Cu")
		(net "CLK_100M_DB2000_CPU1_BCLK0_DN")
	)
	(segment
		(start 66.81216 -198.171816)
		(end 66.545206 -198.81723)
		(width 0.13208)
		(layer "B.Cu")
		(net "CLK_100M_DB2000_CPU1_BCLK0_DN")
	)
	(segment
		(start 70.395846 -179.898548)
		(end 67.237356 -179.898548)
		(width 0.13208)
		(layer "B.Cu")
		(net "CLK_100M_DB2000_CPU1_BCLK0_DN")
	)
	(segment
		(start 228.27488 -136.032748)
		(end 227.81768 -135.575548)
		(width 0.13208)
		(layer "B.Cu")
		(net "CLK_100M_DB2000_CPU1_BCLK0_DN")
	)
	(segment
		(start 101.101144 -237.095538)
		(end 101.114606 -237.087918)
		(width 0.0889)
		(layer "B.Cu")
		(net "CLK_100M_DB2000_CPU1_BCLK0_DN")
	)
	(segment
		(start 61.19114 -232.969308)
		(end 61.402976 -233.480356)
		(width 0.13208)
		(layer "B.Cu")
		(net "CLK_100M_DB2000_CPU1_BCLK0_DN")
	)
	(segment
		(start 89.352882 -237.909862)
		(end 89.367614 -237.901226)
		(width 0.0889)
		(layer "B.Cu")
		(net "CLK_100M_DB2000_CPU1_BCLK0_DN")
	)
	(segment
		(start 90.292682 -237.909862)
		(end 90.307414 -237.901226)
		(width 0.0889)
		(layer "B.Cu")
		(net "CLK_100M_DB2000_CPU1_BCLK0_DN")
	)
	(segment
		(start 99.690682 -237.909862)
		(end 99.705414 -237.901226)
		(width 0.0889)
		(layer "B.Cu")
		(net "CLK_100M_DB2000_CPU1_BCLK0_DN")
	)
	(segment
		(start 100.630482 -237.909862)
		(end 100.645214 -237.901226)
		(width 0.0889)
		(layer "B.Cu")
		(net "CLK_100M_DB2000_CPU1_BCLK0_DN")
	)
	(segment
		(start 66.07683 -236.219238)
		(end 75.95743 -239.217708)
		(width 0.13208)
		(layer "B.Cu")
		(net "CLK_100M_DB2000_CPU1_BCLK0_DN")
	)
	(segment
		(start 101.115368 -237.08741)
		(end 101.12629 -237.08106)
		(width 0.0889)
		(layer "B.Cu")
		(net "CLK_100M_DB2000_CPU1_BCLK0_DN")
	)
	(segment
		(start 64.6811 -182.454804)
		(end 64.6811 -186.373262)
		(width 0.13208)
		(layer "B.Cu")
		(net "CLK_100M_DB2000_CPU1_BCLK0_DN")
	)
	(segment
		(start 61.19114 -203.471018)
		(end 61.19114 -232.969308)
		(width 0.13208)
		(layer "B.Cu")
		(net "CLK_100M_DB2000_CPU1_BCLK0_DN")
	)
	(segment
		(start 101.114606 -237.087918)
		(end 101.115368 -237.08741)
		(width 0.0889)
		(layer "B.Cu")
		(net "CLK_100M_DB2000_CPU1_BCLK0_DN")
	)
	(segment
		(start 94.991682 -237.909862)
		(end 95.006414 -237.901226)
		(width 0.0889)
		(layer "B.Cu")
		(net "CLK_100M_DB2000_CPU1_BCLK0_DN")
	)
	(segment
		(start 75.3872 -175.783748)
		(end 74.554334 -175.783748)
		(width 0.13208)
		(layer "B.Cu")
		(net "CLK_100M_DB2000_CPU1_BCLK0_DN")
	)
	(segment
		(start 71.47306 -178.821334)
		(end 70.395846 -179.898548)
		(width 0.13208)
		(layer "B.Cu")
		(net "CLK_100M_DB2000_CPU1_BCLK0_DN")
	)
	(segment
		(start 100.927662 -237.40491)
		(end 100.928932 -237.34014)
		(width 0.0889)
		(layer "B.Cu")
		(net "CLK_100M_DB2000_CPU1_BCLK0_DN")
	)
	(segment
		(start 185.403998 -142.133828)
		(end 108.057188 -142.133828)
		(width 0.13208)
		(layer "B.Cu")
		(net "CLK_100M_DB2000_CPU1_BCLK0_DN")
	)
	(segment
		(start 227.26904 -134.226808)
		(end 225.156776 -134.226808)
		(width 0.13208)
		(layer "B.Cu")
		(net "CLK_100M_DB2000_CPU1_BCLK0_DN")
	)
	(segment
		(start 229.21468 -135.626348)
		(end 228.80828 -136.032748)
		(width 0.13208)
		(layer "B.Cu")
		(net "CLK_100M_DB2000_CPU1_BCLK0_DN")
	)
	(segment
		(start 97.815654 -237.907322)
		(end 97.826068 -237.901226)
		(width 0.0889)
		(layer "B.Cu")
		(net "CLK_100M_DB2000_CPU1_BCLK0_DN")
	)
	(segment
		(start 95.931482 -237.909862)
		(end 95.946214 -237.901226)
		(width 0.0889)
		(layer "B.Cu")
		(net "CLK_100M_DB2000_CPU1_BCLK0_DN")
	)
	(segment
		(start 66.66357 -192.342262)
		(end 66.81216 -192.700402)
		(width 0.13208)
		(layer "B.Cu")
		(net "CLK_100M_DB2000_CPU1_BCLK0_DN")
	)
	(segment
		(start 108.057188 -142.133828)
		(end 106.275124 -142.871952)
		(width 0.13208)
		(layer "B.Cu")
		(net "CLK_100M_DB2000_CPU1_BCLK0_DN")
	)
	(segment
		(start 94.051882 -237.909862)
		(end 94.066614 -237.901226)
		(width 0.0889)
		(layer "B.Cu")
		(net "CLK_100M_DB2000_CPU1_BCLK0_DN")
	)
	(segment
		(start 62.378844 -201.922888)
		(end 61.446664 -202.854814)
		(width 0.13208)
		(layer "B.Cu")
		(net "CLK_100M_DB2000_CPU1_BCLK0_DN")
	)
	(segment
		(start 91.237054 -237.907322)
		(end 91.247468 -237.901226)
		(width 0.0889)
		(layer "B.Cu")
		(net "CLK_100M_DB2000_CPU1_BCLK0_DN")
	)
	(segment
		(start 65.787016 -191.030352)
		(end 66.663062 -192.341246)
		(width 0.13208)
		(layer "B.Cu")
		(net "CLK_100M_DB2000_CPU1_BCLK0_DN")
	)
	(segment
		(start 101.61524 -237.411514)
		(end 101.302566 -237.411514)
		(width 0.0889)
		(layer "B.Cu")
		(net "CLK_100M_DB2000_CPU1_BCLK0_DN")
	)
	(segment
		(start 101.489764 -237.087156)
		(end 101.491288 -237.087918)
		(width 0.0889)
		(layer "B.Cu")
		(net "CLK_100M_DB2000_CPU1_BCLK0_DN")
	)
	(segment
		(start 101.672898 -237.353856)
		(end 101.61524 -237.411514)
		(width 0.0889)
		(layer "B.Cu")
		(net "CLK_100M_DB2000_CPU1_BCLK0_DN")
	)
	(segment
		(start 83.57362 -239.661192)
		(end 83.609434 -239.625378)
		(width 0.0889)
		(layer "B.Cu")
		(net "CLK_100M_DB2000_CPU1_BCLK0_DN")
	)
	(segment
		(start 100.927916 -237.425738)
		(end 100.927916 -237.411514)
		(width 0.0889)
		(layer "B.Cu")
		(net "CLK_100M_DB2000_CPU1_BCLK0_DN")
	)
	(segment
		(start 100.927916 -237.405164)
		(end 100.927662 -237.40491)
		(width 0.0889)
		(layer "B.Cu")
		(net "CLK_100M_DB2000_CPU1_BCLK0_DN")
	)
	(segment
		(start 91.621864 -237.901226)
		(end 91.632278 -237.907322)
		(width 0.0889)
		(layer "B.Cu")
		(net "CLK_100M_DB2000_CPU1_BCLK0_DN")
	)
	(segment
		(start 75.95743 -239.217708)
		(end 78.512162 -239.661192)
		(width 0.13208)
		(layer "B.Cu")
		(net "CLK_100M_DB2000_CPU1_BCLK0_DN")
	)
	(segment
		(start 64.6811 -186.373262)
		(end 65.439798 -190.192152)
		(width 0.13208)
		(layer "B.Cu")
		(net "CLK_100M_DB2000_CPU1_BCLK0_DN")
	)
	(segment
		(start 227.81768 -134.775448)
		(end 227.26904 -134.226808)
		(width 0.13208)
		(layer "B.Cu")
		(net "CLK_100M_DB2000_CPU1_BCLK0_DN")
	)
	(segment
		(start 101.045772 -237.131098)
		(end 101.101144 -237.095538)
		(width 0.0889)
		(layer "B.Cu")
		(net "CLK_100M_DB2000_CPU1_BCLK0_DN")
	)
	(segment
		(start 98.200464 -237.901226)
		(end 98.210878 -237.907322)
		(width 0.0889)
		(layer "B.Cu")
		(net "CLK_100M_DB2000_CPU1_BCLK0_DN")
	)
	(segment
		(start 225.156776 -134.226808)
		(end 185.403998 -142.133828)
		(width 0.13208)
		(layer "B.Cu")
		(net "CLK_100M_DB2000_CPU1_BCLK0_DN")
	)
	(segment
		(start 78.512162 -239.661192)
		(end 83.551522 -239.661192)
		(width 0.13208)
		(layer "B.Cu")
		(net "CLK_100M_DB2000_CPU1_BCLK0_DN")
	)
	(segment
		(start 88.4174 -237.907322)
		(end 88.427814 -237.901226)
		(width 0.0889)
		(layer "B.Cu")
		(net "CLK_100M_DB2000_CPU1_BCLK0_DN")
	)
	(segment
		(start 67.237356 -179.898548)
		(end 64.6811 -182.454804)
		(width 0.13208)
		(layer "B.Cu")
		(net "CLK_100M_DB2000_CPU1_BCLK0_DN")
	)
	(segment
		(start 72.523604 -176.624742)
		(end 71.819008 -177.679604)
		(width 0.13208)
		(layer "B.Cu")
		(net "CLK_100M_DB2000_CPU1_BCLK0_DN")
	)
	(arc
		(start 97.26041 -237.901226)
		(mid 97.537223 -237.977062)
		(end 97.815654 -237.907322)
		(width 0.0889)
		(layer "B.Cu")
		(net "CLK_100M_DB2000_CPU1_BCLK0_DN")
	)
	(arc
		(start 90.307414 -237.901226)
		(mid 90.494612 -237.851083)
		(end 90.68181 -237.901226)
		(width 0.0889)
		(layer "B.Cu")
		(net "CLK_100M_DB2000_CPU1_BCLK0_DN")
	)
	(arc
		(start 100.645214 -237.901226)
		(mid 100.848695 -237.700422)
		(end 100.927916 -237.425738)
		(width 0.0889)
		(layer "B.Cu")
		(net "CLK_100M_DB2000_CPU1_BCLK0_DN")
	)
	(arc
		(start 88.427814 -237.901226)
		(mid 88.615012 -237.851083)
		(end 88.80221 -237.901226)
		(width 0.0889)
		(layer "B.Cu")
		(net "CLK_100M_DB2000_CPU1_BCLK0_DN")
	)
	(arc
		(start 94.066614 -237.901226)
		(mid 94.253812 -237.851083)
		(end 94.44101 -237.901226)
		(width 0.0889)
		(layer "B.Cu")
		(net "CLK_100M_DB2000_CPU1_BCLK0_DN")
	)
	(arc
		(start 91.632278 -237.907322)
		(mid 91.910456 -237.977014)
		(end 92.187014 -237.901226)
		(width 0.0889)
		(layer "B.Cu")
		(net "CLK_100M_DB2000_CPU1_BCLK0_DN")
	)
	(arc
		(start 98.765614 -237.901226)
		(mid 98.952812 -237.851083)
		(end 99.14001 -237.901226)
		(width 0.0889)
		(layer "B.Cu")
		(net "CLK_100M_DB2000_CPU1_BCLK0_DN")
	)
	(arc
		(start 98.210878 -237.907322)
		(mid 98.489056 -237.977014)
		(end 98.765614 -237.901226)
		(width 0.0889)
		(layer "B.Cu")
		(net "CLK_100M_DB2000_CPU1_BCLK0_DN")
	)
	(arc
		(start 97.826068 -237.901226)
		(mid 98.013266 -237.851083)
		(end 98.200464 -237.901226)
		(width 0.0889)
		(layer "B.Cu")
		(net "CLK_100M_DB2000_CPU1_BCLK0_DN")
	)
	(arc
		(start 87.410036 -237.960154)
		(mid 87.447227 -237.928136)
		(end 87.488268 -237.901226)
		(width 0.0889)
		(layer "B.Cu")
		(net "CLK_100M_DB2000_CPU1_BCLK0_DN")
	)
	(arc
		(start 95.38081 -237.901226)
		(mid 95.655039 -237.977151)
		(end 95.931482 -237.909862)
		(width 0.0889)
		(layer "B.Cu")
		(net "CLK_100M_DB2000_CPU1_BCLK0_DN")
	)
	(arc
		(start 100.927916 -237.411514)
		(mid 100.927904 -237.408339)
		(end 100.927916 -237.405164)
		(width 0.0889)
		(layer "B.Cu")
		(net "CLK_100M_DB2000_CPU1_BCLK0_DN")
	)
	(arc
		(start 101.12629 -237.08106)
		(mid 101.30882 -237.037036)
		(end 101.489764 -237.087156)
		(width 0.0889)
		(layer "B.Cu")
		(net "CLK_100M_DB2000_CPU1_BCLK0_DN")
	)
	(arc
		(start 90.68181 -237.901226)
		(mid 90.958623 -237.977062)
		(end 91.237054 -237.907322)
		(width 0.0889)
		(layer "B.Cu")
		(net "CLK_100M_DB2000_CPU1_BCLK0_DN")
	)
	(arc
		(start 89.367614 -237.901226)
		(mid 89.554812 -237.851083)
		(end 89.74201 -237.901226)
		(width 0.0889)
		(layer "B.Cu")
		(net "CLK_100M_DB2000_CPU1_BCLK0_DN")
	)
	(arc
		(start 87.862664 -237.901226)
		(mid 88.139223 -237.976935)
		(end 88.4174 -237.907322)
		(width 0.0889)
		(layer "B.Cu")
		(net "CLK_100M_DB2000_CPU1_BCLK0_DN")
	)
	(arc
		(start 87.488268 -237.901226)
		(mid 87.675466 -237.851083)
		(end 87.862664 -237.901226)
		(width 0.0889)
		(layer "B.Cu")
		(net "CLK_100M_DB2000_CPU1_BCLK0_DN")
	)
	(arc
		(start 93.126814 -237.901226)
		(mid 93.314012 -237.851083)
		(end 93.50121 -237.901226)
		(width 0.0889)
		(layer "B.Cu")
		(net "CLK_100M_DB2000_CPU1_BCLK0_DN")
	)
	(arc
		(start 96.886014 -237.901226)
		(mid 97.073212 -237.851083)
		(end 97.26041 -237.901226)
		(width 0.0889)
		(layer "B.Cu")
		(net "CLK_100M_DB2000_CPU1_BCLK0_DN")
	)
	(arc
		(start 92.187014 -237.901226)
		(mid 92.374212 -237.851083)
		(end 92.56141 -237.901226)
		(width 0.0889)
		(layer "B.Cu")
		(net "CLK_100M_DB2000_CPU1_BCLK0_DN")
	)
	(arc
		(start 95.946214 -237.901226)
		(mid 96.133412 -237.851083)
		(end 96.32061 -237.901226)
		(width 0.0889)
		(layer "B.Cu")
		(net "CLK_100M_DB2000_CPU1_BCLK0_DN")
	)
	(arc
		(start 94.44101 -237.901226)
		(mid 94.715239 -237.977151)
		(end 94.991682 -237.909862)
		(width 0.0889)
		(layer "B.Cu")
		(net "CLK_100M_DB2000_CPU1_BCLK0_DN")
	)
	(arc
		(start 92.56141 -237.901226)
		(mid 92.835639 -237.977151)
		(end 93.112082 -237.909862)
		(width 0.0889)
		(layer "B.Cu")
		(net "CLK_100M_DB2000_CPU1_BCLK0_DN")
	)
	(arc
		(start 93.50121 -237.901226)
		(mid 93.775439 -237.977151)
		(end 94.051882 -237.909862)
		(width 0.0889)
		(layer "B.Cu")
		(net "CLK_100M_DB2000_CPU1_BCLK0_DN")
	)
	(arc
		(start 91.247468 -237.901226)
		(mid 91.434666 -237.851083)
		(end 91.621864 -237.901226)
		(width 0.0889)
		(layer "B.Cu")
		(net "CLK_100M_DB2000_CPU1_BCLK0_DN")
	)
	(arc
		(start 101.538278 -237.115604)
		(mid 101.622631 -237.195285)
		(end 101.665024 -237.30331)
		(width 0.0889)
		(layer "B.Cu")
		(net "CLK_100M_DB2000_CPU1_BCLK0_DN")
	)
	(arc
		(start 96.32061 -237.901226)
		(mid 96.594839 -237.977151)
		(end 96.871282 -237.909862)
		(width 0.0889)
		(layer "B.Cu")
		(net "CLK_100M_DB2000_CPU1_BCLK0_DN")
	)
	(arc
		(start 100.928932 -237.34014)
		(mid 100.961116 -237.220945)
		(end 101.045772 -237.131098)
		(width 0.0889)
		(layer "B.Cu")
		(net "CLK_100M_DB2000_CPU1_BCLK0_DN")
	)
	(arc
		(start 99.705414 -237.901226)
		(mid 99.892612 -237.851083)
		(end 100.07981 -237.901226)
		(width 0.0889)
		(layer "B.Cu")
		(net "CLK_100M_DB2000_CPU1_BCLK0_DN")
	)
	(arc
		(start 100.07981 -237.901226)
		(mid 100.354039 -237.977151)
		(end 100.630482 -237.909862)
		(width 0.0889)
		(layer "B.Cu")
		(net "CLK_100M_DB2000_CPU1_BCLK0_DN")
	)
	(arc
		(start 95.006414 -237.901226)
		(mid 95.193612 -237.851083)
		(end 95.38081 -237.901226)
		(width 0.0889)
		(layer "B.Cu")
		(net "CLK_100M_DB2000_CPU1_BCLK0_DN")
	)
	(arc
		(start 99.14001 -237.901226)
		(mid 99.414239 -237.977151)
		(end 99.690682 -237.909862)
		(width 0.0889)
		(layer "B.Cu")
		(net "CLK_100M_DB2000_CPU1_BCLK0_DN")
	)
	(arc
		(start 89.74201 -237.901226)
		(mid 90.016239 -237.977151)
		(end 90.292682 -237.909862)
		(width 0.0889)
		(layer "B.Cu")
		(net "CLK_100M_DB2000_CPU1_BCLK0_DN")
	)
	(arc
		(start 88.80221 -237.901226)
		(mid 89.076439 -237.977151)
		(end 89.352882 -237.909862)
		(width 0.0889)
		(layer "B.Cu")
		(net "CLK_100M_DB2000_CPU1_BCLK0_DN")
	)
	(segment
		(start 370.38788 -235.505752)
		(end 370.38788 -234.970066)
		(width 0.13208)
		(layer "F.Cu")
		(net "CLK_100M_DB2000_CPU0_BCLK3_DP")
	)
	(segment
		(start 242.686586 -133.093968)
		(end 242.9764 -133.383782)
		(width 0.13208)
		(layer "F.Cu")
		(net "CLK_100M_DB2000_CPU0_BCLK3_DP")
	)
	(segment
		(start 236.127544 -131.175506)
		(end 238.046006 -133.093968)
		(width 0.13208)
		(layer "F.Cu")
		(net "CLK_100M_DB2000_CPU0_BCLK3_DP")
	)
	(segment
		(start 370.388134 -235.506006)
		(end 370.38788 -235.505752)
		(width 0.13208)
		(layer "F.Cu")
		(net "CLK_100M_DB2000_CPU0_BCLK3_DP")
	)
	(segment
		(start 236.24794 -129.517902)
		(end 236.127544 -129.638298)
		(width 0.13208)
		(layer "F.Cu")
		(net "CLK_100M_DB2000_CPU0_BCLK3_DP")
	)
	(segment
		(start 242.9764 -133.383782)
		(end 242.9764 -133.707124)
		(width 0.13208)
		(layer "F.Cu")
		(net "CLK_100M_DB2000_CPU0_BCLK3_DP")
	)
	(segment
		(start 236.127544 -129.638298)
		(end 236.127544 -131.175506)
		(width 0.13208)
		(layer "F.Cu")
		(net "CLK_100M_DB2000_CPU0_BCLK3_DP")
	)
	(segment
		(start 242.9764 -133.707124)
		(end 243.27866 -134.009384)
		(width 0.13208)
		(layer "F.Cu")
		(net "CLK_100M_DB2000_CPU0_BCLK3_DP")
	)
	(segment
		(start 238.046006 -133.093968)
		(end 242.686586 -133.093968)
		(width 0.13208)
		(layer "F.Cu")
		(net "CLK_100M_DB2000_CPU0_BCLK3_DP")
	)
	(via
		(at 243.27866 -134.009384)
		(size 0.508)
		(drill 0.254)
		(layers "F.Cu" "B.Cu")
		(net "CLK_100M_DB2000_CPU0_BCLK3_DP")
	)
	(via
		(at 370.38788 -234.970066)
		(size 0.4572)
		(drill 0.2032)
		(layers "F.Cu" "B.Cu")
		(net "CLK_100M_DB2000_CPU0_BCLK3_DP")
	)
	(segment
		(start 362.532676 -166.142416)
		(end 368.1222 -170.729402)
		(width 0.13208)
		(layer "B.Cu")
		(net "CLK_100M_DB2000_CPU0_BCLK3_DP")
	)
	(segment
		(start 390.41324 -234.252008)
		(end 389.834882 -234.49153)
		(width 0.13208)
		(layer "B.Cu")
		(net "CLK_100M_DB2000_CPU0_BCLK3_DP")
	)
	(segment
		(start 243.27866 -134.009384)
		(end 242.9764 -133.707124)
		(width 0.13208)
		(layer "B.Cu")
		(net "CLK_100M_DB2000_CPU0_BCLK3_DP")
	)
	(segment
		(start 270.119602 -136.266682)
		(end 270.503396 -136.342882)
		(width 0.13208)
		(layer "B.Cu")
		(net "CLK_100M_DB2000_CPU0_BCLK3_DP")
	)
	(segment
		(start 264.91057 -135.103108)
		(end 265.008106 -135.249666)
		(width 0.13208)
		(layer "B.Cu")
		(net "CLK_100M_DB2000_CPU0_BCLK3_DP")
	)
	(segment
		(start 270.503396 -136.342882)
		(end 270.6497 -136.245092)
		(width 0.13208)
		(layer "B.Cu")
		(net "CLK_100M_DB2000_CPU0_BCLK3_DP")
	)
	(segment
		(start 265.008106 -135.249666)
		(end 265.392154 -135.325866)
		(width 0.13208)
		(layer "B.Cu")
		(net "CLK_100M_DB2000_CPU0_BCLK3_DP")
	)
	(segment
		(start 375.758964 -236.099604)
		(end 375.744232 -236.10824)
		(width 0.0889)
		(layer "B.Cu")
		(net "CLK_100M_DB2000_CPU0_BCLK3_DP")
	)
	(segment
		(start 266.835128 -135.48614)
		(end 267.603224 -135.638794)
		(width 0.13208)
		(layer "B.Cu")
		(net "CLK_100M_DB2000_CPU0_BCLK3_DP")
	)
	(segment
		(start 389.310626 -234.573826)
		(end 389.243316 -234.73664)
		(width 0.13208)
		(layer "B.Cu")
		(net "CLK_100M_DB2000_CPU0_BCLK3_DP")
	)
	(segment
		(start 269.50416 -136.017254)
		(end 270.021812 -136.120124)
		(width 0.13208)
		(layer "B.Cu")
		(net "CLK_100M_DB2000_CPU0_BCLK3_DP")
	)
	(segment
		(start 372.54561 -171.668186)
		(end 375.878598 -173.895766)
		(width 0.13208)
		(layer "B.Cu")
		(net "CLK_100M_DB2000_CPU0_BCLK3_DP")
	)
	(segment
		(start 385.60248 -236.18825)
		(end 385.567936 -236.222794)
		(width 0.0889)
		(layer "B.Cu")
		(net "CLK_100M_DB2000_CPU0_BCLK3_DP")
	)
	(segment
		(start 343.462102 -154.93492)
		(end 356.497382 -163.643564)
		(width 0.13208)
		(layer "B.Cu")
		(net "CLK_100M_DB2000_CPU0_BCLK3_DP")
	)
	(segment
		(start 271.630648 -136.567164)
		(end 271.776952 -136.469374)
		(width 0.13208)
		(layer "B.Cu")
		(net "CLK_100M_DB2000_CPU0_BCLK3_DP")
	)
	(segment
		(start 387.913118 -235.28782)
		(end 387.182614 -235.590334)
		(width 0.13208)
		(layer "B.Cu")
		(net "CLK_100M_DB2000_CPU0_BCLK3_DP")
	)
	(segment
		(start 242.9764 -133.52018)
		(end 243.062252 -133.434328)
		(width 0.13208)
		(layer "B.Cu")
		(net "CLK_100M_DB2000_CPU0_BCLK3_DP")
	)
	(segment
		(start 388.185152 -186.202574)
		(end 391.328656 -193.791078)
		(width 0.13208)
		(layer "B.Cu")
		(net "CLK_100M_DB2000_CPU0_BCLK3_DP")
	)
	(segment
		(start 266.688824 -135.58393)
		(end 266.835128 -135.48614)
		(width 0.13208)
		(layer "B.Cu")
		(net "CLK_100M_DB2000_CPU0_BCLK3_DP")
	)
	(segment
		(start 370.206778 -235.29798)
		(end 370.201444 -235.294932)
		(width 0.0889)
		(layer "B.Cu")
		(net "CLK_100M_DB2000_CPU0_BCLK3_DP")
	)
	(segment
		(start 267.603224 -135.638794)
		(end 267.701014 -135.785352)
		(width 0.13208)
		(layer "B.Cu")
		(net "CLK_100M_DB2000_CPU0_BCLK3_DP")
	)
	(segment
		(start 379.513846 -236.102144)
		(end 379.503432 -236.10824)
		(width 0.0889)
		(layer "B.Cu")
		(net "CLK_100M_DB2000_CPU0_BCLK3_DP")
	)
	(segment
		(start 266.304776 -135.507476)
		(end 266.688824 -135.58393)
		(width 0.13208)
		(layer "B.Cu")
		(net "CLK_100M_DB2000_CPU0_BCLK3_DP")
	)
	(segment
		(start 387.182614 -235.590334)
		(end 386.767832 -236.005116)
		(width 0.13208)
		(layer "B.Cu")
		(net "CLK_100M_DB2000_CPU0_BCLK3_DP")
	)
	(segment
		(start 395.81074 -198.273162)
		(end 395.81074 -228.698298)
		(width 0.13208)
		(layer "B.Cu")
		(net "CLK_100M_DB2000_CPU0_BCLK3_DP")
	)
	(segment
		(start 391.142474 -233.522774)
		(end 390.966452 -233.522774)
		(width 0.13208)
		(layer "B.Cu")
		(net "CLK_100M_DB2000_CPU0_BCLK3_DP")
	)
	(segment
		(start 385.567936 -236.222794)
		(end 385.191762 -236.222794)
		(width 0.0889)
		(layer "B.Cu")
		(net "CLK_100M_DB2000_CPU0_BCLK3_DP")
	)
	(segment
		(start 393.606528 -231.05872)
		(end 393.330176 -231.335072)
		(width 0.13208)
		(layer "B.Cu")
		(net "CLK_100M_DB2000_CPU0_BCLK3_DP")
	)
	(segment
		(start 384.217164 -236.099604)
		(end 384.202432 -236.10824)
		(width 0.0889)
		(layer "B.Cu")
		(net "CLK_100M_DB2000_CPU0_BCLK3_DP")
	)
	(segment
		(start 390.689592 -233.975656)
		(end 390.41324 -234.252008)
		(width 0.13208)
		(layer "B.Cu")
		(net "CLK_100M_DB2000_CPU0_BCLK3_DP")
	)
	(segment
		(start 265.538458 -135.228076)
		(end 266.206986 -135.360918)
		(width 0.13208)
		(layer "B.Cu")
		(net "CLK_100M_DB2000_CPU0_BCLK3_DP")
	)
	(segment
		(start 390.689592 -233.799634)
		(end 390.689592 -233.975656)
		(width 0.13208)
		(layer "B.Cu")
		(net "CLK_100M_DB2000_CPU0_BCLK3_DP")
	)
	(segment
		(start 390.966452 -233.522774)
		(end 390.689592 -233.799634)
		(width 0.13208)
		(layer "B.Cu")
		(net "CLK_100M_DB2000_CPU0_BCLK3_DP")
	)
	(segment
		(start 375.878598 -173.895766)
		(end 388.185152 -186.202574)
		(width 0.13208)
		(layer "B.Cu")
		(net "CLK_100M_DB2000_CPU0_BCLK3_DP")
	)
	(segment
		(start 370.017802 -235.02747)
		(end 370.075206 -234.970066)
		(width 0.0889)
		(layer "B.Cu")
		(net "CLK_100M_DB2000_CPU0_BCLK3_DP")
	)
	(segment
		(start 242.9764 -133.707124)
		(end 242.9764 -133.52018)
		(width 0.13208)
		(layer "B.Cu")
		(net "CLK_100M_DB2000_CPU0_BCLK3_DP")
	)
	(segment
		(start 356.497382 -163.643564)
		(end 362.532676 -166.142416)
		(width 0.13208)
		(layer "B.Cu")
		(net "CLK_100M_DB2000_CPU0_BCLK3_DP")
	)
	(segment
		(start 391.695686 -232.79354)
		(end 391.418826 -233.0704)
		(width 0.13208)
		(layer "B.Cu")
		(net "CLK_100M_DB2000_CPU0_BCLK3_DP")
	)
	(segment
		(start 385.842764 -236.18952)
		(end 385.841494 -236.18825)
		(width 0.13208)
		(layer "B.Cu")
		(net "CLK_100M_DB2000_CPU0_BCLK3_DP")
	)
	(segment
		(start 385.841494 -236.18825)
		(end 385.624578 -236.18825)
		(width 0.13208)
		(layer "B.Cu")
		(net "CLK_100M_DB2000_CPU0_BCLK3_DP")
	)
	(segment
		(start 392.877294 -231.611932)
		(end 392.877294 -231.787954)
		(width 0.13208)
		(layer "B.Cu")
		(net "CLK_100M_DB2000_CPU0_BCLK3_DP")
	)
	(segment
		(start 268.085062 -135.861806)
		(end 268.231366 -135.764016)
		(width 0.13208)
		(layer "B.Cu")
		(net "CLK_100M_DB2000_CPU0_BCLK3_DP")
	)
	(segment
		(start 386.322824 -236.18952)
		(end 385.842764 -236.18952)
		(width 0.13208)
		(layer "B.Cu")
		(net "CLK_100M_DB2000_CPU0_BCLK3_DP")
	)
	(segment
		(start 389.243316 -234.73664)
		(end 388.504684 -235.04271)
		(width 0.13208)
		(layer "B.Cu")
		(net "CLK_100M_DB2000_CPU0_BCLK3_DP")
	)
	(segment
		(start 395.134846 -229.35438)
		(end 395.134846 -229.530402)
		(width 0.13208)
		(layer "B.Cu")
		(net "CLK_100M_DB2000_CPU0_BCLK3_DP")
	)
	(segment
		(start 394.612622 -229.876604)
		(end 394.335762 -230.153464)
		(width 0.13208)
		(layer "B.Cu")
		(net "CLK_100M_DB2000_CPU0_BCLK3_DP")
	)
	(segment
		(start 395.81074 -228.698298)
		(end 395.70025 -228.964998)
		(width 0.13208)
		(layer "B.Cu")
		(net "CLK_100M_DB2000_CPU0_BCLK3_DP")
	)
	(segment
		(start 393.883388 -230.605838)
		(end 393.606528 -230.882698)
		(width 0.13208)
		(layer "B.Cu")
		(net "CLK_100M_DB2000_CPU0_BCLK3_DP")
	)
	(segment
		(start 377.638564 -236.099604)
		(end 377.623832 -236.10824)
		(width 0.0889)
		(layer "B.Cu")
		(net "CLK_100M_DB2000_CPU0_BCLK3_DP")
	)
	(segment
		(start 394.335762 -230.329486)
		(end 394.05941 -230.605838)
		(width 0.13208)
		(layer "B.Cu")
		(net "CLK_100M_DB2000_CPU0_BCLK3_DP")
	)
	(segment
		(start 392.600942 -232.064306)
		(end 392.42492 -232.064306)
		(width 0.13208)
		(layer "B.Cu")
		(net "CLK_100M_DB2000_CPU0_BCLK3_DP")
	)
	(segment
		(start 266.206986 -135.360918)
		(end 266.304776 -135.507476)
		(width 0.13208)
		(layer "B.Cu")
		(net "CLK_100M_DB2000_CPU0_BCLK3_DP")
	)
	(segment
		(start 304.983388 -143.073628)
		(end 318.285368 -143.073628)
		(width 0.13208)
		(layer "B.Cu")
		(net "CLK_100M_DB2000_CPU0_BCLK3_DP")
	)
	(segment
		(start 370.075206 -234.970066)
		(end 370.38788 -234.970066)
		(width 0.0889)
		(layer "B.Cu")
		(net "CLK_100M_DB2000_CPU0_BCLK3_DP")
	)
	(segment
		(start 268.973808 -136.038844)
		(end 269.357856 -136.115044)
		(width 0.13208)
		(layer "B.Cu")
		(net "CLK_100M_DB2000_CPU0_BCLK3_DP")
	)
	(segment
		(start 393.606528 -230.882698)
		(end 393.606528 -231.05872)
		(width 0.13208)
		(layer "B.Cu")
		(net "CLK_100M_DB2000_CPU0_BCLK3_DP")
	)
	(segment
		(start 373.874792 -236.102144)
		(end 373.864378 -236.10824)
		(width 0.0889)
		(layer "B.Cu")
		(net "CLK_100M_DB2000_CPU0_BCLK3_DP")
	)
	(segment
		(start 395.587474 -229.077774)
		(end 395.411452 -229.077774)
		(width 0.13208)
		(layer "B.Cu")
		(net "CLK_100M_DB2000_CPU0_BCLK3_DP")
	)
	(segment
		(start 388.504684 -235.04271)
		(end 388.342124 -234.975146)
		(width 0.13208)
		(layer "B.Cu")
		(net "CLK_100M_DB2000_CPU0_BCLK3_DP")
	)
	(segment
		(start 392.14806 -232.517188)
		(end 391.871708 -232.79354)
		(width 0.13208)
		(layer "B.Cu")
		(net "CLK_100M_DB2000_CPU0_BCLK3_DP")
	)
	(segment
		(start 394.788644 -229.876604)
		(end 394.612622 -229.876604)
		(width 0.13208)
		(layer "B.Cu")
		(net "CLK_100M_DB2000_CPU0_BCLK3_DP")
	)
	(segment
		(start 393.154154 -231.335072)
		(end 392.877294 -231.611932)
		(width 0.13208)
		(layer "B.Cu")
		(net "CLK_100M_DB2000_CPU0_BCLK3_DP")
	)
	(segment
		(start 386.767832 -236.005116)
		(end 386.322824 -236.18952)
		(width 0.13208)
		(layer "B.Cu")
		(net "CLK_100M_DB2000_CPU0_BCLK3_DP")
	)
	(segment
		(start 394.335762 -230.153464)
		(end 394.335762 -230.329486)
		(width 0.13208)
		(layer "B.Cu")
		(net "CLK_100M_DB2000_CPU0_BCLK3_DP")
	)
	(segment
		(start 387.980428 -235.125006)
		(end 387.913118 -235.28782)
		(width 0.13208)
		(layer "B.Cu")
		(net "CLK_100M_DB2000_CPU0_BCLK3_DP")
	)
	(segment
		(start 395.134846 -229.530402)
		(end 394.788644 -229.876604)
		(width 0.13208)
		(layer "B.Cu")
		(net "CLK_100M_DB2000_CPU0_BCLK3_DP")
	)
	(segment
		(start 394.05941 -230.605838)
		(end 393.883388 -230.605838)
		(width 0.13208)
		(layer "B.Cu")
		(net "CLK_100M_DB2000_CPU0_BCLK3_DP")
	)
	(segment
		(start 378.578364 -236.099604)
		(end 378.563632 -236.10824)
		(width 0.0889)
		(layer "B.Cu")
		(net "CLK_100M_DB2000_CPU0_BCLK3_DP")
	)
	(segment
		(start 267.701014 -135.785352)
		(end 268.085062 -135.861806)
		(width 0.13208)
		(layer "B.Cu")
		(net "CLK_100M_DB2000_CPU0_BCLK3_DP")
	)
	(segment
		(start 264.140442 -134.949946)
		(end 264.91057 -135.103108)
		(width 0.13208)
		(layer "B.Cu")
		(net "CLK_100M_DB2000_CPU0_BCLK3_DP")
	)
	(segment
		(start 388.342124 -234.975146)
		(end 387.980428 -235.125006)
		(width 0.13208)
		(layer "B.Cu")
		(net "CLK_100M_DB2000_CPU0_BCLK3_DP")
	)
	(segment
		(start 270.021812 -136.120124)
		(end 270.119602 -136.266682)
		(width 0.13208)
		(layer "B.Cu")
		(net "CLK_100M_DB2000_CPU0_BCLK3_DP")
	)
	(segment
		(start 268.231366 -135.764016)
		(end 268.876018 -135.892032)
		(width 0.13208)
		(layer "B.Cu")
		(net "CLK_100M_DB2000_CPU0_BCLK3_DP")
	)
	(segment
		(start 271.2466 -136.490964)
		(end 271.630648 -136.567164)
		(width 0.13208)
		(layer "B.Cu")
		(net "CLK_100M_DB2000_CPU0_BCLK3_DP")
	)
	(segment
		(start 392.877294 -231.787954)
		(end 392.600942 -232.064306)
		(width 0.13208)
		(layer "B.Cu")
		(net "CLK_100M_DB2000_CPU0_BCLK3_DP")
	)
	(segment
		(start 391.418826 -233.0704)
		(end 391.418826 -233.246422)
		(width 0.13208)
		(layer "B.Cu")
		(net "CLK_100M_DB2000_CPU0_BCLK3_DP")
	)
	(segment
		(start 318.285368 -143.073628)
		(end 341.016844 -152.489662)
		(width 0.13208)
		(layer "B.Cu")
		(net "CLK_100M_DB2000_CPU0_BCLK3_DP")
	)
	(segment
		(start 389.834882 -234.49153)
		(end 389.672322 -234.42422)
		(width 0.13208)
		(layer "B.Cu")
		(net "CLK_100M_DB2000_CPU0_BCLK3_DP")
	)
	(segment
		(start 393.330176 -231.335072)
		(end 393.154154 -231.335072)
		(width 0.13208)
		(layer "B.Cu")
		(net "CLK_100M_DB2000_CPU0_BCLK3_DP")
	)
	(segment
		(start 391.418826 -233.246422)
		(end 391.142474 -233.522774)
		(width 0.13208)
		(layer "B.Cu")
		(net "CLK_100M_DB2000_CPU0_BCLK3_DP")
	)
	(segment
		(start 371.261386 -171.27855)
		(end 372.54561 -171.668186)
		(width 0.13208)
		(layer "B.Cu")
		(net "CLK_100M_DB2000_CPU0_BCLK3_DP")
	)
	(segment
		(start 370.201444 -235.294932)
		(end 370.191792 -235.289344)
		(width 0.0889)
		(layer "B.Cu")
		(net "CLK_100M_DB2000_CPU0_BCLK3_DP")
	)
	(segment
		(start 369.44808 -171.27855)
		(end 371.261386 -171.27855)
		(width 0.13208)
		(layer "B.Cu")
		(net "CLK_100M_DB2000_CPU0_BCLK3_DP")
	)
	(segment
		(start 374.819164 -236.099604)
		(end 374.804432 -236.10824)
		(width 0.0889)
		(layer "B.Cu")
		(net "CLK_100M_DB2000_CPU0_BCLK3_DP")
	)
	(segment
		(start 395.411452 -229.077774)
		(end 395.134846 -229.35438)
		(width 0.13208)
		(layer "B.Cu")
		(net "CLK_100M_DB2000_CPU0_BCLK3_DP")
	)
	(segment
		(start 380.453392 -236.102144)
		(end 380.442978 -236.10824)
		(width 0.0889)
		(layer "B.Cu")
		(net "CLK_100M_DB2000_CPU0_BCLK3_DP")
	)
	(segment
		(start 268.876018 -135.892032)
		(end 268.973808 -136.038844)
		(width 0.13208)
		(layer "B.Cu")
		(net "CLK_100M_DB2000_CPU0_BCLK3_DP")
	)
	(segment
		(start 383.277364 -236.099604)
		(end 383.262632 -236.10824)
		(width 0.0889)
		(layer "B.Cu")
		(net "CLK_100M_DB2000_CPU0_BCLK3_DP")
	)
	(segment
		(start 248.755662 -133.434328)
		(end 264.140442 -134.949946)
		(width 0.13208)
		(layer "B.Cu")
		(net "CLK_100M_DB2000_CPU0_BCLK3_DP")
	)
	(segment
		(start 341.016844 -152.489662)
		(end 343.462102 -154.93492)
		(width 0.13208)
		(layer "B.Cu")
		(net "CLK_100M_DB2000_CPU0_BCLK3_DP")
	)
	(segment
		(start 270.6497 -136.245092)
		(end 271.14881 -136.344152)
		(width 0.13208)
		(layer "B.Cu")
		(net "CLK_100M_DB2000_CPU0_BCLK3_DP")
	)
	(segment
		(start 392.14806 -232.341166)
		(end 392.14806 -232.517188)
		(width 0.13208)
		(layer "B.Cu")
		(net "CLK_100M_DB2000_CPU0_BCLK3_DP")
	)
	(segment
		(start 391.328656 -193.791078)
		(end 395.81074 -198.273162)
		(width 0.13208)
		(layer "B.Cu")
		(net "CLK_100M_DB2000_CPU0_BCLK3_DP")
	)
	(segment
		(start 395.70025 -228.964998)
		(end 395.587474 -229.077774)
		(width 0.13208)
		(layer "B.Cu")
		(net "CLK_100M_DB2000_CPU0_BCLK3_DP")
	)
	(segment
		(start 372.935246 -236.102144)
		(end 372.924832 -236.10824)
		(width 0.0889)
		(layer "B.Cu")
		(net "CLK_100M_DB2000_CPU0_BCLK3_DP")
	)
	(segment
		(start 384.767074 -236.108748)
		(end 384.767582 -236.107986)
		(width 0.0889)
		(layer "B.Cu")
		(net "CLK_100M_DB2000_CPU0_BCLK3_DP")
	)
	(segment
		(start 392.42492 -232.064306)
		(end 392.14806 -232.341166)
		(width 0.13208)
		(layer "B.Cu")
		(net "CLK_100M_DB2000_CPU0_BCLK3_DP")
	)
	(segment
		(start 271.14881 -136.344152)
		(end 271.2466 -136.490964)
		(width 0.13208)
		(layer "B.Cu")
		(net "CLK_100M_DB2000_CPU0_BCLK3_DP")
	)
	(segment
		(start 269.357856 -136.115044)
		(end 269.50416 -136.017254)
		(width 0.13208)
		(layer "B.Cu")
		(net "CLK_100M_DB2000_CPU0_BCLK3_DP")
	)
	(segment
		(start 385.624578 -236.18825)
		(end 385.60248 -236.18825)
		(width 0.0889)
		(layer "B.Cu")
		(net "CLK_100M_DB2000_CPU0_BCLK3_DP")
	)
	(segment
		(start 371.059964 -236.099604)
		(end 371.045232 -236.10824)
		(width 0.0889)
		(layer "B.Cu")
		(net "CLK_100M_DB2000_CPU0_BCLK3_DP")
	)
	(segment
		(start 243.062252 -133.434328)
		(end 248.755662 -133.434328)
		(width 0.13208)
		(layer "B.Cu")
		(net "CLK_100M_DB2000_CPU0_BCLK3_DP")
	)
	(segment
		(start 271.776952 -136.469374)
		(end 304.983388 -143.073628)
		(width 0.13208)
		(layer "B.Cu")
		(net "CLK_100M_DB2000_CPU0_BCLK3_DP")
	)
	(segment
		(start 265.392154 -135.325866)
		(end 265.538458 -135.228076)
		(width 0.13208)
		(layer "B.Cu")
		(net "CLK_100M_DB2000_CPU0_BCLK3_DP")
	)
	(segment
		(start 368.1222 -170.729402)
		(end 369.44808 -171.27855)
		(width 0.13208)
		(layer "B.Cu")
		(net "CLK_100M_DB2000_CPU0_BCLK3_DP")
	)
	(segment
		(start 389.672322 -234.42422)
		(end 389.310626 -234.573826)
		(width 0.13208)
		(layer "B.Cu")
		(net "CLK_100M_DB2000_CPU0_BCLK3_DP")
	)
	(segment
		(start 371.999764 -236.099604)
		(end 371.985032 -236.10824)
		(width 0.0889)
		(layer "B.Cu")
		(net "CLK_100M_DB2000_CPU0_BCLK3_DP")
	)
	(segment
		(start 391.871708 -232.79354)
		(end 391.695686 -232.79354)
		(width 0.13208)
		(layer "B.Cu")
		(net "CLK_100M_DB2000_CPU0_BCLK3_DP")
	)
	(arc
		(start 378.189236 -236.10824)
		(mid 377.915007 -236.032315)
		(end 377.638564 -236.099604)
		(width 0.0889)
		(layer "B.Cu")
		(net "CLK_100M_DB2000_CPU0_BCLK3_DP")
	)
	(arc
		(start 376.309636 -236.10824)
		(mid 376.035407 -236.032315)
		(end 375.758964 -236.099604)
		(width 0.0889)
		(layer "B.Cu")
		(net "CLK_100M_DB2000_CPU0_BCLK3_DP")
	)
	(arc
		(start 385.191762 -236.222794)
		(mid 384.971889 -236.193797)
		(end 384.767074 -236.108748)
		(width 0.0889)
		(layer "B.Cu")
		(net "CLK_100M_DB2000_CPU0_BCLK3_DP")
	)
	(arc
		(start 378.563632 -236.10824)
		(mid 378.376434 -236.158383)
		(end 378.189236 -236.10824)
		(width 0.0889)
		(layer "B.Cu")
		(net "CLK_100M_DB2000_CPU0_BCLK3_DP")
	)
	(arc
		(start 383.828036 -236.10824)
		(mid 383.553807 -236.032315)
		(end 383.277364 -236.099604)
		(width 0.0889)
		(layer "B.Cu")
		(net "CLK_100M_DB2000_CPU0_BCLK3_DP")
	)
	(arc
		(start 377.249436 -236.10824)
		(mid 376.966734 -236.032498)
		(end 376.684032 -236.10824)
		(width 0.0889)
		(layer "B.Cu")
		(net "CLK_100M_DB2000_CPU0_BCLK3_DP")
	)
	(arc
		(start 372.924832 -236.10824)
		(mid 372.737634 -236.158383)
		(end 372.550436 -236.10824)
		(width 0.0889)
		(layer "B.Cu")
		(net "CLK_100M_DB2000_CPU0_BCLK3_DP")
	)
	(arc
		(start 379.129036 -236.10824)
		(mid 378.854807 -236.032315)
		(end 378.578364 -236.099604)
		(width 0.0889)
		(layer "B.Cu")
		(net "CLK_100M_DB2000_CPU0_BCLK3_DP")
	)
	(arc
		(start 373.489982 -236.10824)
		(mid 373.213423 -236.032531)
		(end 372.935246 -236.102144)
		(width 0.0889)
		(layer "B.Cu")
		(net "CLK_100M_DB2000_CPU0_BCLK3_DP")
	)
	(arc
		(start 370.483384 -235.783882)
		(mid 370.409393 -235.504316)
		(end 370.206778 -235.29798)
		(width 0.0889)
		(layer "B.Cu")
		(net "CLK_100M_DB2000_CPU0_BCLK3_DP")
	)
	(arc
		(start 374.430036 -236.10824)
		(mid 374.153223 -236.032404)
		(end 373.874792 -236.102144)
		(width 0.0889)
		(layer "B.Cu")
		(net "CLK_100M_DB2000_CPU0_BCLK3_DP")
	)
	(arc
		(start 382.888236 -236.10824)
		(mid 382.605534 -236.032498)
		(end 382.322832 -236.10824)
		(width 0.0889)
		(layer "B.Cu")
		(net "CLK_100M_DB2000_CPU0_BCLK3_DP")
	)
	(arc
		(start 376.684032 -236.10824)
		(mid 376.496834 -236.158383)
		(end 376.309636 -236.10824)
		(width 0.0889)
		(layer "B.Cu")
		(net "CLK_100M_DB2000_CPU0_BCLK3_DP")
	)
	(arc
		(start 384.202432 -236.10824)
		(mid 384.015234 -236.158383)
		(end 383.828036 -236.10824)
		(width 0.0889)
		(layer "B.Cu")
		(net "CLK_100M_DB2000_CPU0_BCLK3_DP")
	)
	(arc
		(start 380.068582 -236.10824)
		(mid 379.792023 -236.032531)
		(end 379.513846 -236.102144)
		(width 0.0889)
		(layer "B.Cu")
		(net "CLK_100M_DB2000_CPU0_BCLK3_DP")
	)
	(arc
		(start 377.623832 -236.10824)
		(mid 377.436634 -236.158383)
		(end 377.249436 -236.10824)
		(width 0.0889)
		(layer "B.Cu")
		(net "CLK_100M_DB2000_CPU0_BCLK3_DP")
	)
	(arc
		(start 373.864378 -236.10824)
		(mid 373.67718 -236.158383)
		(end 373.489982 -236.10824)
		(width 0.0889)
		(layer "B.Cu")
		(net "CLK_100M_DB2000_CPU0_BCLK3_DP")
	)
	(arc
		(start 382.322832 -236.10824)
		(mid 382.135634 -236.158383)
		(end 381.948436 -236.10824)
		(width 0.0889)
		(layer "B.Cu")
		(net "CLK_100M_DB2000_CPU0_BCLK3_DP")
	)
	(arc
		(start 374.804432 -236.10824)
		(mid 374.617234 -236.158383)
		(end 374.430036 -236.10824)
		(width 0.0889)
		(layer "B.Cu")
		(net "CLK_100M_DB2000_CPU0_BCLK3_DP")
	)
	(arc
		(start 370.191792 -235.289344)
		(mid 370.076053 -235.17752)
		(end 370.017802 -235.02747)
		(width 0.0889)
		(layer "B.Cu")
		(net "CLK_100M_DB2000_CPU0_BCLK3_DP")
	)
	(arc
		(start 375.369836 -236.10824)
		(mid 375.095607 -236.032315)
		(end 374.819164 -236.099604)
		(width 0.0889)
		(layer "B.Cu")
		(net "CLK_100M_DB2000_CPU0_BCLK3_DP")
	)
	(arc
		(start 371.045232 -236.10824)
		(mid 370.670757 -236.108194)
		(end 370.483384 -235.783882)
		(width 0.0889)
		(layer "B.Cu")
		(net "CLK_100M_DB2000_CPU0_BCLK3_DP")
	)
	(arc
		(start 381.948436 -236.10824)
		(mid 381.665734 -236.032498)
		(end 381.383032 -236.10824)
		(width 0.0889)
		(layer "B.Cu")
		(net "CLK_100M_DB2000_CPU0_BCLK3_DP")
	)
	(arc
		(start 381.383032 -236.10824)
		(mid 381.195834 -236.158383)
		(end 381.008636 -236.10824)
		(width 0.0889)
		(layer "B.Cu")
		(net "CLK_100M_DB2000_CPU0_BCLK3_DP")
	)
	(arc
		(start 375.744232 -236.10824)
		(mid 375.557034 -236.158383)
		(end 375.369836 -236.10824)
		(width 0.0889)
		(layer "B.Cu")
		(net "CLK_100M_DB2000_CPU0_BCLK3_DP")
	)
	(arc
		(start 380.442978 -236.10824)
		(mid 380.25578 -236.158383)
		(end 380.068582 -236.10824)
		(width 0.0889)
		(layer "B.Cu")
		(net "CLK_100M_DB2000_CPU0_BCLK3_DP")
	)
	(arc
		(start 383.262632 -236.10824)
		(mid 383.075434 -236.158383)
		(end 382.888236 -236.10824)
		(width 0.0889)
		(layer "B.Cu")
		(net "CLK_100M_DB2000_CPU0_BCLK3_DP")
	)
	(arc
		(start 379.503432 -236.10824)
		(mid 379.316234 -236.158383)
		(end 379.129036 -236.10824)
		(width 0.0889)
		(layer "B.Cu")
		(net "CLK_100M_DB2000_CPU0_BCLK3_DP")
	)
	(arc
		(start 372.550436 -236.10824)
		(mid 372.276207 -236.032315)
		(end 371.999764 -236.099604)
		(width 0.0889)
		(layer "B.Cu")
		(net "CLK_100M_DB2000_CPU0_BCLK3_DP")
	)
	(arc
		(start 381.008636 -236.10824)
		(mid 380.731823 -236.032404)
		(end 380.453392 -236.102144)
		(width 0.0889)
		(layer "B.Cu")
		(net "CLK_100M_DB2000_CPU0_BCLK3_DP")
	)
	(arc
		(start 384.767582 -236.107986)
		(mid 384.493465 -236.032343)
		(end 384.217164 -236.099604)
		(width 0.0889)
		(layer "B.Cu")
		(net "CLK_100M_DB2000_CPU0_BCLK3_DP")
	)
	(arc
		(start 371.610636 -236.10824)
		(mid 371.336407 -236.032315)
		(end 371.059964 -236.099604)
		(width 0.0889)
		(layer "B.Cu")
		(net "CLK_100M_DB2000_CPU0_BCLK3_DP")
	)
	(arc
		(start 371.985032 -236.10824)
		(mid 371.797834 -236.158383)
		(end 371.610636 -236.10824)
		(width 0.0889)
		(layer "B.Cu")
		(net "CLK_100M_DB2000_CPU0_BCLK3_DP")
	)
	(segment
		(start 242.579144 -133.353048)
		(end 242.71732 -133.491224)
		(width 0.13208)
		(layer "F.Cu")
		(net "CLK_100M_DB2000_CPU0_BCLK3_DN")
	)
	(segment
		(start 235.868464 -129.638298)
		(end 235.868464 -131.282948)
		(width 0.13208)
		(layer "F.Cu")
		(net "CLK_100M_DB2000_CPU0_BCLK3_DN")
	)
	(segment
		(start 235.868464 -131.282948)
		(end 237.938564 -133.353048)
		(width 0.13208)
		(layer "F.Cu")
		(net "CLK_100M_DB2000_CPU0_BCLK3_DN")
	)
	(segment
		(start 242.71732 -133.707124)
		(end 242.41506 -134.009384)
		(width 0.13208)
		(layer "F.Cu")
		(net "CLK_100M_DB2000_CPU0_BCLK3_DN")
	)
	(segment
		(start 242.71732 -133.491224)
		(end 242.71732 -133.707124)
		(width 0.13208)
		(layer "F.Cu")
		(net "CLK_100M_DB2000_CPU0_BCLK3_DN")
	)
	(segment
		(start 369.448334 -235.506006)
		(end 369.44808 -235.505752)
		(width 0.13208)
		(layer "F.Cu")
		(net "CLK_100M_DB2000_CPU0_BCLK3_DN")
	)
	(segment
		(start 369.44808 -235.505752)
		(end 369.44808 -234.970066)
		(width 0.13208)
		(layer "F.Cu")
		(net "CLK_100M_DB2000_CPU0_BCLK3_DN")
	)
	(segment
		(start 237.938564 -133.353048)
		(end 242.579144 -133.353048)
		(width 0.13208)
		(layer "F.Cu")
		(net "CLK_100M_DB2000_CPU0_BCLK3_DN")
	)
	(segment
		(start 235.748068 -129.517902)
		(end 235.868464 -129.638298)
		(width 0.13208)
		(layer "F.Cu")
		(net "CLK_100M_DB2000_CPU0_BCLK3_DN")
	)
	(via
		(at 369.44808 -234.970066)
		(size 0.4572)
		(drill 0.2032)
		(layers "F.Cu" "B.Cu")
		(net "CLK_100M_DB2000_CPU0_BCLK3_DN")
	)
	(via
		(at 242.41506 -134.009384)
		(size 0.508)
		(drill 0.254)
		(layers "F.Cu" "B.Cu")
		(net "CLK_100M_DB2000_CPU0_BCLK3_DN")
	)
	(segment
		(start 378.658882 -236.273594)
		(end 378.64415 -236.28223)
		(width 0.0889)
		(layer "B.Cu")
		(net "CLK_100M_DB2000_CPU0_BCLK3_DN")
	)
	(segment
		(start 376.043952 -173.694344)
		(end 388.404862 -186.055762)
		(width 0.13208)
		(layer "B.Cu")
		(net "CLK_100M_DB2000_CPU0_BCLK3_DN")
	)
	(segment
		(start 271.827244 -136.214358)
		(end 271.827244 -136.21512)
		(width 0.13208)
		(layer "B.Cu")
		(net "CLK_100M_DB2000_CPU0_BCLK3_DN")
	)
	(segment
		(start 343.627456 -154.733498)
		(end 356.620318 -163.413694)
		(width 0.13208)
		(layer "B.Cu")
		(net "CLK_100M_DB2000_CPU0_BCLK3_DN")
	)
	(segment
		(start 371.140482 -236.273594)
		(end 371.130068 -236.27969)
		(width 0.0889)
		(layer "B.Cu")
		(net "CLK_100M_DB2000_CPU0_BCLK3_DN")
	)
	(segment
		(start 385.60248 -236.44733)
		(end 385.56819 -236.41304)
		(width 0.0889)
		(layer "B.Cu")
		(net "CLK_100M_DB2000_CPU0_BCLK3_DN")
	)
	(segment
		(start 387.329426 -235.810044)
		(end 386.914644 -236.224826)
		(width 0.13208)
		(layer "B.Cu")
		(net "CLK_100M_DB2000_CPU0_BCLK3_DN")
	)
	(segment
		(start 362.667296 -165.917626)
		(end 368.257074 -170.504612)
		(width 0.13208)
		(layer "B.Cu")
		(net "CLK_100M_DB2000_CPU0_BCLK3_DN")
	)
	(segment
		(start 368.257074 -170.504612)
		(end 369.499642 -171.01947)
		(width 0.13208)
		(layer "B.Cu")
		(net "CLK_100M_DB2000_CPU0_BCLK3_DN")
	)
	(segment
		(start 381.478536 -236.273594)
		(end 381.468122 -236.27969)
		(width 0.0889)
		(layer "B.Cu")
		(net "CLK_100M_DB2000_CPU0_BCLK3_DN")
	)
	(segment
		(start 271.827244 -136.21512)
		(end 305.009042 -142.814548)
		(width 0.13208)
		(layer "B.Cu")
		(net "CLK_100M_DB2000_CPU0_BCLK3_DN")
	)
	(segment
		(start 385.83108 -236.4486)
		(end 385.82981 -236.44733)
		(width 0.13208)
		(layer "B.Cu")
		(net "CLK_100M_DB2000_CPU0_BCLK3_DN")
	)
	(segment
		(start 388.404862 -186.055762)
		(end 391.548366 -193.644266)
		(width 0.13208)
		(layer "B.Cu")
		(net "CLK_100M_DB2000_CPU0_BCLK3_DN")
	)
	(segment
		(start 395.91996 -229.11181)
		(end 390.560052 -234.471718)
		(width 0.13208)
		(layer "B.Cu")
		(net "CLK_100M_DB2000_CPU0_BCLK3_DN")
	)
	(segment
		(start 384.297682 -236.273594)
		(end 384.28295 -236.28223)
		(width 0.0889)
		(layer "B.Cu")
		(net "CLK_100M_DB2000_CPU0_BCLK3_DN")
	)
	(segment
		(start 371.299994 -171.01947)
		(end 372.657624 -171.431204)
		(width 0.13208)
		(layer "B.Cu")
		(net "CLK_100M_DB2000_CPU0_BCLK3_DN")
	)
	(segment
		(start 242.41506 -134.009384)
		(end 242.71732 -133.707124)
		(width 0.13208)
		(layer "B.Cu")
		(net "CLK_100M_DB2000_CPU0_BCLK3_DN")
	)
	(segment
		(start 248.768616 -133.175248)
		(end 264.178542 -134.693152)
		(width 0.13208)
		(layer "B.Cu")
		(net "CLK_100M_DB2000_CPU0_BCLK3_DN")
	)
	(segment
		(start 359.61447 -164.653468)
		(end 362.667296 -165.917626)
		(width 0.13208)
		(layer "B.Cu")
		(net "CLK_100M_DB2000_CPU0_BCLK3_DN")
	)
	(segment
		(start 369.760754 -234.970066)
		(end 369.44808 -234.970066)
		(width 0.0889)
		(layer "B.Cu")
		(net "CLK_100M_DB2000_CPU0_BCLK3_DN")
	)
	(segment
		(start 377.719082 -236.273594)
		(end 377.708668 -236.27969)
		(width 0.0889)
		(layer "B.Cu")
		(net "CLK_100M_DB2000_CPU0_BCLK3_DN")
	)
	(segment
		(start 356.620318 -163.413694)
		(end 359.61447 -164.653468)
		(width 0.13208)
		(layer "B.Cu")
		(net "CLK_100M_DB2000_CPU0_BCLK3_DN")
	)
	(segment
		(start 372.657624 -171.431204)
		(end 376.043952 -173.694344)
		(width 0.13208)
		(layer "B.Cu")
		(net "CLK_100M_DB2000_CPU0_BCLK3_DN")
	)
	(segment
		(start 374.899682 -236.273594)
		(end 374.88495 -236.28223)
		(width 0.0889)
		(layer "B.Cu")
		(net "CLK_100M_DB2000_CPU0_BCLK3_DN")
	)
	(segment
		(start 379.598682 -236.273594)
		(end 379.58395 -236.28223)
		(width 0.0889)
		(layer "B.Cu")
		(net "CLK_100M_DB2000_CPU0_BCLK3_DN")
	)
	(segment
		(start 385.82981 -236.44733)
		(end 385.624578 -236.44733)
		(width 0.13208)
		(layer "B.Cu")
		(net "CLK_100M_DB2000_CPU0_BCLK3_DN")
	)
	(segment
		(start 242.71732 -133.412738)
		(end 242.95481 -133.175248)
		(width 0.13208)
		(layer "B.Cu")
		(net "CLK_100M_DB2000_CPU0_BCLK3_DN")
	)
	(segment
		(start 242.71732 -133.707124)
		(end 242.71732 -133.412738)
		(width 0.13208)
		(layer "B.Cu")
		(net "CLK_100M_DB2000_CPU0_BCLK3_DN")
	)
	(segment
		(start 372.080282 -236.273594)
		(end 372.06555 -236.28223)
		(width 0.0889)
		(layer "B.Cu")
		(net "CLK_100M_DB2000_CPU0_BCLK3_DN")
	)
	(segment
		(start 385.56819 -236.41304)
		(end 385.191508 -236.41304)
		(width 0.0889)
		(layer "B.Cu")
		(net "CLK_100M_DB2000_CPU0_BCLK3_DN")
	)
	(segment
		(start 318.33693 -142.814548)
		(end 341.163656 -152.269952)
		(width 0.13208)
		(layer "B.Cu")
		(net "CLK_100M_DB2000_CPU0_BCLK3_DN")
	)
	(segment
		(start 391.548366 -193.644266)
		(end 396.06982 -198.16572)
		(width 0.13208)
		(layer "B.Cu")
		(net "CLK_100M_DB2000_CPU0_BCLK3_DN")
	)
	(segment
		(start 242.95481 -133.175248)
		(end 248.768616 -133.175248)
		(width 0.13208)
		(layer "B.Cu")
		(net "CLK_100M_DB2000_CPU0_BCLK3_DN")
	)
	(segment
		(start 305.009042 -142.814548)
		(end 318.33693 -142.814548)
		(width 0.13208)
		(layer "B.Cu")
		(net "CLK_100M_DB2000_CPU0_BCLK3_DN")
	)
	(segment
		(start 375.839482 -236.273594)
		(end 375.82475 -236.28223)
		(width 0.0889)
		(layer "B.Cu")
		(net "CLK_100M_DB2000_CPU0_BCLK3_DN")
	)
	(segment
		(start 396.06982 -198.16572)
		(end 396.06982 -228.74986)
		(width 0.13208)
		(layer "B.Cu")
		(net "CLK_100M_DB2000_CPU0_BCLK3_DN")
	)
	(segment
		(start 396.06982 -228.74986)
		(end 395.91996 -229.11181)
		(width 0.13208)
		(layer "B.Cu")
		(net "CLK_100M_DB2000_CPU0_BCLK3_DN")
	)
	(segment
		(start 370.105432 -235.459524)
		(end 370.102638 -235.458)
		(width 0.0889)
		(layer "B.Cu")
		(net "CLK_100M_DB2000_CPU0_BCLK3_DN")
	)
	(segment
		(start 370.102638 -235.458)
		(end 370.099336 -235.455968)
		(width 0.0889)
		(layer "B.Cu")
		(net "CLK_100M_DB2000_CPU0_BCLK3_DN")
	)
	(segment
		(start 370.292884 -235.802424)
		(end 370.292884 -235.783882)
		(width 0.0889)
		(layer "B.Cu")
		(net "CLK_100M_DB2000_CPU0_BCLK3_DN")
	)
	(segment
		(start 385.624578 -236.44733)
		(end 385.60248 -236.44733)
		(width 0.0889)
		(layer "B.Cu")
		(net "CLK_100M_DB2000_CPU0_BCLK3_DN")
	)
	(segment
		(start 386.914644 -236.224826)
		(end 386.374386 -236.4486)
		(width 0.13208)
		(layer "B.Cu")
		(net "CLK_100M_DB2000_CPU0_BCLK3_DN")
	)
	(segment
		(start 341.163656 -152.269952)
		(end 343.627456 -154.733498)
		(width 0.13208)
		(layer "B.Cu")
		(net "CLK_100M_DB2000_CPU0_BCLK3_DN")
	)
	(segment
		(start 383.357882 -236.273594)
		(end 383.347468 -236.27969)
		(width 0.0889)
		(layer "B.Cu")
		(net "CLK_100M_DB2000_CPU0_BCLK3_DN")
	)
	(segment
		(start 369.499642 -171.01947)
		(end 371.299994 -171.01947)
		(width 0.13208)
		(layer "B.Cu")
		(net "CLK_100M_DB2000_CPU0_BCLK3_DN")
	)
	(segment
		(start 369.82654 -235.035852)
		(end 369.760754 -234.970066)
		(width 0.0889)
		(layer "B.Cu")
		(net "CLK_100M_DB2000_CPU0_BCLK3_DN")
	)
	(segment
		(start 376.779536 -236.273594)
		(end 376.769122 -236.27969)
		(width 0.0889)
		(layer "B.Cu")
		(net "CLK_100M_DB2000_CPU0_BCLK3_DN")
	)
	(segment
		(start 386.374386 -236.4486)
		(end 385.83108 -236.4486)
		(width 0.13208)
		(layer "B.Cu")
		(net "CLK_100M_DB2000_CPU0_BCLK3_DN")
	)
	(segment
		(start 370.106956 -235.460286)
		(end 370.105432 -235.459524)
		(width 0.0889)
		(layer "B.Cu")
		(net "CLK_100M_DB2000_CPU0_BCLK3_DN")
	)
	(segment
		(start 373.020082 -236.273594)
		(end 373.00535 -236.28223)
		(width 0.0889)
		(layer "B.Cu")
		(net "CLK_100M_DB2000_CPU0_BCLK3_DN")
	)
	(segment
		(start 370.114322 -235.464604)
		(end 370.106956 -235.460286)
		(width 0.0889)
		(layer "B.Cu")
		(net "CLK_100M_DB2000_CPU0_BCLK3_DN")
	)
	(segment
		(start 264.178542 -134.693152)
		(end 271.827244 -136.214358)
		(width 0.13208)
		(layer "B.Cu")
		(net "CLK_100M_DB2000_CPU0_BCLK3_DN")
	)
	(segment
		(start 390.560052 -234.471718)
		(end 387.329426 -235.810044)
		(width 0.13208)
		(layer "B.Cu")
		(net "CLK_100M_DB2000_CPU0_BCLK3_DN")
	)
	(arc
		(start 377.153932 -236.273594)
		(mid 376.966734 -236.223451)
		(end 376.779536 -236.273594)
		(width 0.0889)
		(layer "B.Cu")
		(net "CLK_100M_DB2000_CPU0_BCLK3_DN")
	)
	(arc
		(start 370.099336 -235.455968)
		(mid 369.919684 -235.286532)
		(end 369.829334 -235.05668)
		(width 0.0889)
		(layer "B.Cu")
		(net "CLK_100M_DB2000_CPU0_BCLK3_DN")
	)
	(arc
		(start 383.347468 -236.27969)
		(mid 383.06929 -236.349382)
		(end 382.792732 -236.273594)
		(width 0.0889)
		(layer "B.Cu")
		(net "CLK_100M_DB2000_CPU0_BCLK3_DN")
	)
	(arc
		(start 370.292884 -235.783882)
		(mid 370.245205 -235.600982)
		(end 370.114322 -235.464604)
		(width 0.0889)
		(layer "B.Cu")
		(net "CLK_100M_DB2000_CPU0_BCLK3_DN")
	)
	(arc
		(start 373.00535 -236.28223)
		(mid 372.728909 -236.349396)
		(end 372.454678 -236.273594)
		(width 0.0889)
		(layer "B.Cu")
		(net "CLK_100M_DB2000_CPU0_BCLK3_DN")
	)
	(arc
		(start 385.191508 -236.41304)
		(mid 384.922327 -236.377474)
		(end 384.67157 -236.27334)
		(width 0.0889)
		(layer "B.Cu")
		(net "CLK_100M_DB2000_CPU0_BCLK3_DN")
	)
	(arc
		(start 384.28295 -236.28223)
		(mid 384.006509 -236.349396)
		(end 383.732278 -236.273594)
		(width 0.0889)
		(layer "B.Cu")
		(net "CLK_100M_DB2000_CPU0_BCLK3_DN")
	)
	(arc
		(start 377.708668 -236.27969)
		(mid 377.43049 -236.349382)
		(end 377.153932 -236.273594)
		(width 0.0889)
		(layer "B.Cu")
		(net "CLK_100M_DB2000_CPU0_BCLK3_DN")
	)
	(arc
		(start 384.67157 -236.27334)
		(mid 384.484597 -236.223484)
		(end 384.297682 -236.273594)
		(width 0.0889)
		(layer "B.Cu")
		(net "CLK_100M_DB2000_CPU0_BCLK3_DN")
	)
	(arc
		(start 374.88495 -236.28223)
		(mid 374.608509 -236.349396)
		(end 374.334278 -236.273594)
		(width 0.0889)
		(layer "B.Cu")
		(net "CLK_100M_DB2000_CPU0_BCLK3_DN")
	)
	(arc
		(start 378.64415 -236.28223)
		(mid 378.367709 -236.349396)
		(end 378.093478 -236.273594)
		(width 0.0889)
		(layer "B.Cu")
		(net "CLK_100M_DB2000_CPU0_BCLK3_DN")
	)
	(arc
		(start 381.852932 -236.273594)
		(mid 381.665734 -236.223451)
		(end 381.478536 -236.273594)
		(width 0.0889)
		(layer "B.Cu")
		(net "CLK_100M_DB2000_CPU0_BCLK3_DN")
	)
	(arc
		(start 380.538482 -236.273594)
		(mid 380.25578 -236.349336)
		(end 379.973078 -236.273594)
		(width 0.0889)
		(layer "B.Cu")
		(net "CLK_100M_DB2000_CPU0_BCLK3_DN")
	)
	(arc
		(start 372.06555 -236.28223)
		(mid 371.789109 -236.349396)
		(end 371.514878 -236.273594)
		(width 0.0889)
		(layer "B.Cu")
		(net "CLK_100M_DB2000_CPU0_BCLK3_DN")
	)
	(arc
		(start 372.454678 -236.273594)
		(mid 372.26748 -236.223451)
		(end 372.080282 -236.273594)
		(width 0.0889)
		(layer "B.Cu")
		(net "CLK_100M_DB2000_CPU0_BCLK3_DN")
	)
	(arc
		(start 371.514878 -236.273594)
		(mid 371.32768 -236.223451)
		(end 371.140482 -236.273594)
		(width 0.0889)
		(layer "B.Cu")
		(net "CLK_100M_DB2000_CPU0_BCLK3_DN")
	)
	(arc
		(start 376.213878 -236.273594)
		(mid 376.02668 -236.223451)
		(end 375.839482 -236.273594)
		(width 0.0889)
		(layer "B.Cu")
		(net "CLK_100M_DB2000_CPU0_BCLK3_DN")
	)
	(arc
		(start 371.130068 -236.27969)
		(mid 370.57797 -236.275199)
		(end 370.292884 -235.802424)
		(width 0.0889)
		(layer "B.Cu")
		(net "CLK_100M_DB2000_CPU0_BCLK3_DN")
	)
	(arc
		(start 381.468122 -236.27969)
		(mid 381.18969 -236.349504)
		(end 380.912878 -236.273594)
		(width 0.0889)
		(layer "B.Cu")
		(net "CLK_100M_DB2000_CPU0_BCLK3_DN")
	)
	(arc
		(start 373.394478 -236.273594)
		(mid 373.20728 -236.223451)
		(end 373.020082 -236.273594)
		(width 0.0889)
		(layer "B.Cu")
		(net "CLK_100M_DB2000_CPU0_BCLK3_DN")
	)
	(arc
		(start 378.093478 -236.273594)
		(mid 377.90628 -236.223451)
		(end 377.719082 -236.273594)
		(width 0.0889)
		(layer "B.Cu")
		(net "CLK_100M_DB2000_CPU0_BCLK3_DN")
	)
	(arc
		(start 374.334278 -236.273594)
		(mid 374.14708 -236.223451)
		(end 373.959882 -236.273594)
		(width 0.0889)
		(layer "B.Cu")
		(net "CLK_100M_DB2000_CPU0_BCLK3_DN")
	)
	(arc
		(start 379.033278 -236.273594)
		(mid 378.84608 -236.223451)
		(end 378.658882 -236.273594)
		(width 0.0889)
		(layer "B.Cu")
		(net "CLK_100M_DB2000_CPU0_BCLK3_DN")
	)
	(arc
		(start 382.418336 -236.273594)
		(mid 382.135634 -236.349336)
		(end 381.852932 -236.273594)
		(width 0.0889)
		(layer "B.Cu")
		(net "CLK_100M_DB2000_CPU0_BCLK3_DN")
	)
	(arc
		(start 383.732278 -236.273594)
		(mid 383.54508 -236.223451)
		(end 383.357882 -236.273594)
		(width 0.0889)
		(layer "B.Cu")
		(net "CLK_100M_DB2000_CPU0_BCLK3_DN")
	)
	(arc
		(start 376.769122 -236.27969)
		(mid 376.49069 -236.349504)
		(end 376.213878 -236.273594)
		(width 0.0889)
		(layer "B.Cu")
		(net "CLK_100M_DB2000_CPU0_BCLK3_DN")
	)
	(arc
		(start 379.973078 -236.273594)
		(mid 379.78588 -236.223451)
		(end 379.598682 -236.273594)
		(width 0.0889)
		(layer "B.Cu")
		(net "CLK_100M_DB2000_CPU0_BCLK3_DN")
	)
	(arc
		(start 373.959882 -236.273594)
		(mid 373.67718 -236.349336)
		(end 373.394478 -236.273594)
		(width 0.0889)
		(layer "B.Cu")
		(net "CLK_100M_DB2000_CPU0_BCLK3_DN")
	)
	(arc
		(start 369.829334 -235.05668)
		(mid 369.827839 -235.046279)
		(end 369.82654 -235.035852)
		(width 0.0889)
		(layer "B.Cu")
		(net "CLK_100M_DB2000_CPU0_BCLK3_DN")
	)
	(arc
		(start 379.58395 -236.28223)
		(mid 379.307509 -236.349396)
		(end 379.033278 -236.273594)
		(width 0.0889)
		(layer "B.Cu")
		(net "CLK_100M_DB2000_CPU0_BCLK3_DN")
	)
	(arc
		(start 375.274078 -236.273594)
		(mid 375.08688 -236.223451)
		(end 374.899682 -236.273594)
		(width 0.0889)
		(layer "B.Cu")
		(net "CLK_100M_DB2000_CPU0_BCLK3_DN")
	)
	(arc
		(start 380.912878 -236.273594)
		(mid 380.72568 -236.223451)
		(end 380.538482 -236.273594)
		(width 0.0889)
		(layer "B.Cu")
		(net "CLK_100M_DB2000_CPU0_BCLK3_DN")
	)
	(arc
		(start 375.82475 -236.28223)
		(mid 375.548309 -236.349396)
		(end 375.274078 -236.273594)
		(width 0.0889)
		(layer "B.Cu")
		(net "CLK_100M_DB2000_CPU0_BCLK3_DN")
	)
	(arc
		(start 382.792732 -236.273594)
		(mid 382.605534 -236.223451)
		(end 382.418336 -236.273594)
		(width 0.0889)
		(layer "B.Cu")
		(net "CLK_100M_DB2000_CPU0_BCLK3_DN")
	)
	(segment
		(start 237.127542 -130.53441)
		(end 238.76254 -132.169408)
		(width 0.13208)
		(layer "F.Cu")
		(net "CLK_100M_DB2000_CPU0_BCLK2_DP")
	)
	(segment
		(start 237.247938 -129.517902)
		(end 237.127542 -129.638298)
		(width 0.13208)
		(layer "F.Cu")
		(net "CLK_100M_DB2000_CPU0_BCLK2_DP")
	)
	(segment
		(start 238.76254 -132.169408)
		(end 243.345462 -132.169408)
		(width 0.13208)
		(layer "F.Cu")
		(net "CLK_100M_DB2000_CPU0_BCLK2_DP")
	)
	(segment
		(start 243.345462 -132.169408)
		(end 245.39956 -134.223506)
		(width 0.13208)
		(layer "F.Cu")
		(net "CLK_100M_DB2000_CPU0_BCLK2_DP")
	)
	(segment
		(start 350.18218 -236.319822)
		(end 350.182434 -236.319568)
		(width 0.13208)
		(layer "F.Cu")
		(net "CLK_100M_DB2000_CPU0_BCLK2_DP")
	)
	(segment
		(start 350.182434 -236.319568)
		(end 350.182434 -235.783882)
		(width 0.13208)
		(layer "F.Cu")
		(net "CLK_100M_DB2000_CPU0_BCLK2_DP")
	)
	(segment
		(start 245.39956 -135.171688)
		(end 245.70182 -135.473948)
		(width 0.13208)
		(layer "F.Cu")
		(net "CLK_100M_DB2000_CPU0_BCLK2_DP")
	)
	(segment
		(start 245.39956 -134.223506)
		(end 245.39956 -135.171688)
		(width 0.13208)
		(layer "F.Cu")
		(net "CLK_100M_DB2000_CPU0_BCLK2_DP")
	)
	(segment
		(start 237.127542 -129.638298)
		(end 237.127542 -130.53441)
		(width 0.13208)
		(layer "F.Cu")
		(net "CLK_100M_DB2000_CPU0_BCLK2_DP")
	)
	(via
		(at 245.70182 -135.473948)
		(size 0.508)
		(drill 0.254)
		(layers "F.Cu" "B.Cu")
		(net "CLK_100M_DB2000_CPU0_BCLK2_DP")
	)
	(via
		(at 350.182434 -235.783882)
		(size 0.4572)
		(drill 0.2032)
		(layers "F.Cu" "B.Cu")
		(net "CLK_100M_DB2000_CPU0_BCLK2_DP")
	)
	(segment
		(start 246.279416 -141.325346)
		(end 253.654814 -159.131254)
		(width 0.13208)
		(layer "B.Cu")
		(net "CLK_100M_DB2000_CPU0_BCLK2_DP")
	)
	(segment
		(start 340.971632 -236.10824)
		(end 340.986364 -236.099604)
		(width 0.0889)
		(layer "B.Cu")
		(net "CLK_100M_DB2000_CPU0_BCLK2_DP")
	)
	(segment
		(start 339.091778 -236.10824)
		(end 339.102192 -236.102144)
		(width 0.0889)
		(layer "B.Cu")
		(net "CLK_100M_DB2000_CPU0_BCLK2_DP")
	)
	(segment
		(start 322.58762 -240.452148)
		(end 322.71208 -240.327688)
		(width 0.13208)
		(layer "B.Cu")
		(net "CLK_100M_DB2000_CPU0_BCLK2_DP")
	)
	(segment
		(start 323.21754 -240.452148)
		(end 323.59854 -240.452148)
		(width 0.13208)
		(layer "B.Cu")
		(net "CLK_100M_DB2000_CPU0_BCLK2_DP")
	)
	(segment
		(start 334.58023 -237.420404)
		(end 334.58023 -237.411768)
		(width 0.0889)
		(layer "B.Cu")
		(net "CLK_100M_DB2000_CPU0_BCLK2_DP")
	)
	(segment
		(start 344.730832 -236.10824)
		(end 344.741246 -236.102144)
		(width 0.0889)
		(layer "B.Cu")
		(net "CLK_100M_DB2000_CPU0_BCLK2_DP")
	)
	(segment
		(start 324.104 -240.327688)
		(end 324.22846 -240.452148)
		(width 0.13208)
		(layer "B.Cu")
		(net "CLK_100M_DB2000_CPU0_BCLK2_DP")
	)
	(segment
		(start 295.75633 -182.736998)
		(end 298.840398 -185.821066)
		(width 0.13208)
		(layer "B.Cu")
		(net "CLK_100M_DB2000_CPU0_BCLK2_DP")
	)
	(segment
		(start 324.22846 -240.452148)
		(end 328.088498 -240.452148)
		(width 0.13208)
		(layer "B.Cu")
		(net "CLK_100M_DB2000_CPU0_BCLK2_DP")
	)
	(segment
		(start 334.862932 -236.92231)
		(end 334.864456 -236.921548)
		(width 0.0889)
		(layer "B.Cu")
		(net "CLK_100M_DB2000_CPU0_BCLK2_DP")
	)
	(segment
		(start 349.429832 -236.10824)
		(end 349.444564 -236.099604)
		(width 0.0889)
		(layer "B.Cu")
		(net "CLK_100M_DB2000_CPU0_BCLK2_DP")
	)
	(segment
		(start 330.880212 -238.056166)
		(end 331.732382 -238.056166)
		(width 0.13208)
		(layer "B.Cu")
		(net "CLK_100M_DB2000_CPU0_BCLK2_DP")
	)
	(segment
		(start 350.02597 -236.0549)
		(end 350.182434 -235.783882)
		(width 0.0889)
		(layer "B.Cu")
		(net "CLK_100M_DB2000_CPU0_BCLK2_DP")
	)
	(segment
		(start 275.733764 -179.939696)
		(end 289.003232 -179.939696)
		(width 0.13208)
		(layer "B.Cu")
		(net "CLK_100M_DB2000_CPU0_BCLK2_DP")
	)
	(segment
		(start 303.6062 -238.302292)
		(end 304.094896 -238.790988)
		(width 0.13208)
		(layer "B.Cu")
		(net "CLK_100M_DB2000_CPU0_BCLK2_DP")
	)
	(segment
		(start 323.723 -240.327688)
		(end 324.104 -240.327688)
		(width 0.13208)
		(layer "B.Cu")
		(net "CLK_100M_DB2000_CPU0_BCLK2_DP")
	)
	(segment
		(start 310.369458 -241.163348)
		(end 312.084466 -240.452148)
		(width 0.13208)
		(layer "B.Cu")
		(net "CLK_100M_DB2000_CPU0_BCLK2_DP")
	)
	(segment
		(start 245.39956 -136.902698)
		(end 246.279416 -141.325346)
		(width 0.13208)
		(layer "B.Cu")
		(net "CLK_100M_DB2000_CPU0_BCLK2_DP")
	)
	(segment
		(start 312.084466 -240.452148)
		(end 322.58762 -240.452148)
		(width 0.13208)
		(layer "B.Cu")
		(net "CLK_100M_DB2000_CPU0_BCLK2_DP")
	)
	(segment
		(start 253.654814 -159.131254)
		(end 273.564858 -179.041298)
		(width 0.13208)
		(layer "B.Cu")
		(net "CLK_100M_DB2000_CPU0_BCLK2_DP")
	)
	(segment
		(start 322.71208 -240.327688)
		(end 323.09308 -240.327688)
		(width 0.13208)
		(layer "B.Cu")
		(net "CLK_100M_DB2000_CPU0_BCLK2_DP")
	)
	(segment
		(start 302.062388 -197.619366)
		(end 303.361344 -198.919084)
		(width 0.13208)
		(layer "B.Cu")
		(net "CLK_100M_DB2000_CPU0_BCLK2_DP")
	)
	(segment
		(start 349.936816 -236.078776)
		(end 350.02597 -236.0549)
		(width 0.0889)
		(layer "B.Cu")
		(net "CLK_100M_DB2000_CPU0_BCLK2_DP")
	)
	(segment
		(start 323.59854 -240.452148)
		(end 323.723 -240.327688)
		(width 0.13208)
		(layer "B.Cu")
		(net "CLK_100M_DB2000_CPU0_BCLK2_DP")
	)
	(segment
		(start 300.670976 -190.239142)
		(end 300.833536 -190.482474)
		(width 0.13208)
		(layer "B.Cu")
		(net "CLK_100M_DB2000_CPU0_BCLK2_DP")
	)
	(segment
		(start 331.75448 -238.056166)
		(end 331.78877 -238.090456)
		(width 0.0889)
		(layer "B.Cu")
		(net "CLK_100M_DB2000_CPU0_BCLK2_DP")
	)
	(segment
		(start 343.791032 -236.10824)
		(end 343.805764 -236.099604)
		(width 0.0889)
		(layer "B.Cu")
		(net "CLK_100M_DB2000_CPU0_BCLK2_DP")
	)
	(segment
		(start 334.856836 -236.925866)
		(end 334.862932 -236.92231)
		(width 0.0889)
		(layer "B.Cu")
		(net "CLK_100M_DB2000_CPU0_BCLK2_DP")
	)
	(segment
		(start 334.864456 -236.921548)
		(end 334.871822 -236.91723)
		(width 0.0889)
		(layer "B.Cu")
		(net "CLK_100M_DB2000_CPU0_BCLK2_DP")
	)
	(segment
		(start 323.09308 -240.327688)
		(end 323.21754 -240.452148)
		(width 0.13208)
		(layer "B.Cu")
		(net "CLK_100M_DB2000_CPU0_BCLK2_DP")
	)
	(segment
		(start 328.088498 -240.452148)
		(end 328.764138 -240.17224)
		(width 0.13208)
		(layer "B.Cu")
		(net "CLK_100M_DB2000_CPU0_BCLK2_DP")
	)
	(segment
		(start 347.550232 -236.10824)
		(end 347.564964 -236.099604)
		(width 0.0889)
		(layer "B.Cu")
		(net "CLK_100M_DB2000_CPU0_BCLK2_DP")
	)
	(segment
		(start 303.361344 -198.919084)
		(end 303.6062 -199.50938)
		(width 0.13208)
		(layer "B.Cu")
		(net "CLK_100M_DB2000_CPU0_BCLK2_DP")
	)
	(segment
		(start 335.332832 -236.10824)
		(end 335.463896 -236.032548)
		(width 0.0889)
		(layer "B.Cu")
		(net "CLK_100M_DB2000_CPU0_BCLK2_DP")
	)
	(segment
		(start 289.003232 -179.939696)
		(end 295.75633 -182.736998)
		(width 0.13208)
		(layer "B.Cu")
		(net "CLK_100M_DB2000_CPU0_BCLK2_DP")
	)
	(segment
		(start 307.784754 -241.163348)
		(end 310.369458 -241.163348)
		(width 0.13208)
		(layer "B.Cu")
		(net "CLK_100M_DB2000_CPU0_BCLK2_DP")
	)
	(segment
		(start 340.031832 -236.10824)
		(end 340.046564 -236.099604)
		(width 0.0889)
		(layer "B.Cu")
		(net "CLK_100M_DB2000_CPU0_BCLK2_DP")
	)
	(segment
		(start 303.6062 -199.50938)
		(end 303.6062 -238.302292)
		(width 0.13208)
		(layer "B.Cu")
		(net "CLK_100M_DB2000_CPU0_BCLK2_DP")
	)
	(segment
		(start 245.70182 -135.473948)
		(end 245.39956 -135.776208)
		(width 0.13208)
		(layer "B.Cu")
		(net "CLK_100M_DB2000_CPU0_BCLK2_DP")
	)
	(segment
		(start 338.152232 -236.10824)
		(end 338.162646 -236.102144)
		(width 0.0889)
		(layer "B.Cu")
		(net "CLK_100M_DB2000_CPU0_BCLK2_DP")
	)
	(segment
		(start 335.050384 -236.597952)
		(end 335.050384 -236.57941)
		(width 0.0889)
		(layer "B.Cu")
		(net "CLK_100M_DB2000_CPU0_BCLK2_DP")
	)
	(segment
		(start 306.25288 -240.528348)
		(end 307.784754 -241.163348)
		(width 0.13208)
		(layer "B.Cu")
		(net "CLK_100M_DB2000_CPU0_BCLK2_DP")
	)
	(segment
		(start 335.463896 -236.032548)
		(end 335.615534 -236.032548)
		(width 0.0889)
		(layer "B.Cu")
		(net "CLK_100M_DB2000_CPU0_BCLK2_DP")
	)
	(segment
		(start 328.764138 -240.17224)
		(end 330.880212 -238.056166)
		(width 0.13208)
		(layer "B.Cu")
		(net "CLK_100M_DB2000_CPU0_BCLK2_DP")
	)
	(segment
		(start 298.840398 -185.821066)
		(end 300.670976 -190.239142)
		(width 0.13208)
		(layer "B.Cu")
		(net "CLK_100M_DB2000_CPU0_BCLK2_DP")
	)
	(segment
		(start 333.901796 -238.090456)
		(end 334.205834 -237.786418)
		(width 0.0889)
		(layer "B.Cu")
		(net "CLK_100M_DB2000_CPU0_BCLK2_DP")
	)
	(segment
		(start 302.00092 -197.471792)
		(end 302.062388 -197.619366)
		(width 0.13208)
		(layer "B.Cu")
		(net "CLK_100M_DB2000_CPU0_BCLK2_DP")
	)
	(segment
		(start 305.36261 -239.638078)
		(end 306.25288 -240.528348)
		(width 0.13208)
		(layer "B.Cu")
		(net "CLK_100M_DB2000_CPU0_BCLK2_DP")
	)
	(segment
		(start 304.094896 -238.790988)
		(end 305.36261 -239.638078)
		(width 0.13208)
		(layer "B.Cu")
		(net "CLK_100M_DB2000_CPU0_BCLK2_DP")
	)
	(segment
		(start 302.00092 -193.302128)
		(end 302.00092 -197.471792)
		(width 0.13208)
		(layer "B.Cu")
		(net "CLK_100M_DB2000_CPU0_BCLK2_DP")
	)
	(segment
		(start 345.670378 -236.10824)
		(end 345.680792 -236.102144)
		(width 0.0889)
		(layer "B.Cu")
		(net "CLK_100M_DB2000_CPU0_BCLK2_DP")
	)
	(segment
		(start 346.610432 -236.10824)
		(end 346.625164 -236.099604)
		(width 0.0889)
		(layer "B.Cu")
		(net "CLK_100M_DB2000_CPU0_BCLK2_DP")
	)
	(segment
		(start 337.212432 -236.10824)
		(end 337.227164 -236.099604)
		(width 0.0889)
		(layer "B.Cu")
		(net "CLK_100M_DB2000_CPU0_BCLK2_DP")
	)
	(segment
		(start 300.833536 -190.482474)
		(end 302.00092 -193.302128)
		(width 0.13208)
		(layer "B.Cu")
		(net "CLK_100M_DB2000_CPU0_BCLK2_DP")
	)
	(segment
		(start 331.732382 -238.056166)
		(end 331.75448 -238.056166)
		(width 0.0889)
		(layer "B.Cu")
		(net "CLK_100M_DB2000_CPU0_BCLK2_DP")
	)
	(segment
		(start 342.851232 -236.10824)
		(end 342.865964 -236.099604)
		(width 0.0889)
		(layer "B.Cu")
		(net "CLK_100M_DB2000_CPU0_BCLK2_DP")
	)
	(segment
		(start 273.564858 -179.041298)
		(end 275.733764 -179.939696)
		(width 0.13208)
		(layer "B.Cu")
		(net "CLK_100M_DB2000_CPU0_BCLK2_DP")
	)
	(segment
		(start 331.78877 -238.090456)
		(end 333.901796 -238.090456)
		(width 0.0889)
		(layer "B.Cu")
		(net "CLK_100M_DB2000_CPU0_BCLK2_DP")
	)
	(segment
		(start 245.39956 -135.776208)
		(end 245.39956 -136.902698)
		(width 0.13208)
		(layer "B.Cu")
		(net "CLK_100M_DB2000_CPU0_BCLK2_DP")
	)
	(arc
		(start 346.236036 -236.10824)
		(mid 346.423234 -236.158383)
		(end 346.610432 -236.10824)
		(width 0.0889)
		(layer "B.Cu")
		(net "CLK_100M_DB2000_CPU0_BCLK2_DP")
	)
	(arc
		(start 341.911432 -236.10824)
		(mid 342.194134 -236.032498)
		(end 342.476836 -236.10824)
		(width 0.0889)
		(layer "B.Cu")
		(net "CLK_100M_DB2000_CPU0_BCLK2_DP")
	)
	(arc
		(start 338.162646 -236.102144)
		(mid 338.440824 -236.032452)
		(end 338.717382 -236.10824)
		(width 0.0889)
		(layer "B.Cu")
		(net "CLK_100M_DB2000_CPU0_BCLK2_DP")
	)
	(arc
		(start 344.741246 -236.102144)
		(mid 345.019424 -236.032452)
		(end 345.295982 -236.10824)
		(width 0.0889)
		(layer "B.Cu")
		(net "CLK_100M_DB2000_CPU0_BCLK2_DP")
	)
	(arc
		(start 335.615534 -236.032548)
		(mid 335.761857 -236.05181)
		(end 335.898236 -236.10824)
		(width 0.0889)
		(layer "B.Cu")
		(net "CLK_100M_DB2000_CPU0_BCLK2_DP")
	)
	(arc
		(start 340.986364 -236.099604)
		(mid 341.262805 -236.032438)
		(end 341.537036 -236.10824)
		(width 0.0889)
		(layer "B.Cu")
		(net "CLK_100M_DB2000_CPU0_BCLK2_DP")
	)
	(arc
		(start 334.205834 -237.786418)
		(mid 334.467679 -237.679723)
		(end 334.58023 -237.420404)
		(width 0.0889)
		(layer "B.Cu")
		(net "CLK_100M_DB2000_CPU0_BCLK2_DP")
	)
	(arc
		(start 336.272632 -236.10824)
		(mid 336.555334 -236.032498)
		(end 336.838036 -236.10824)
		(width 0.0889)
		(layer "B.Cu")
		(net "CLK_100M_DB2000_CPU0_BCLK2_DP")
	)
	(arc
		(start 341.537036 -236.10824)
		(mid 341.724234 -236.158383)
		(end 341.911432 -236.10824)
		(width 0.0889)
		(layer "B.Cu")
		(net "CLK_100M_DB2000_CPU0_BCLK2_DP")
	)
	(arc
		(start 347.175836 -236.10824)
		(mid 347.363034 -236.158383)
		(end 347.550232 -236.10824)
		(width 0.0889)
		(layer "B.Cu")
		(net "CLK_100M_DB2000_CPU0_BCLK2_DP")
	)
	(arc
		(start 342.476836 -236.10824)
		(mid 342.664034 -236.158383)
		(end 342.851232 -236.10824)
		(width 0.0889)
		(layer "B.Cu")
		(net "CLK_100M_DB2000_CPU0_BCLK2_DP")
	)
	(arc
		(start 348.115636 -236.10824)
		(mid 348.302834 -236.158383)
		(end 348.490032 -236.10824)
		(width 0.0889)
		(layer "B.Cu")
		(net "CLK_100M_DB2000_CPU0_BCLK2_DP")
	)
	(arc
		(start 337.777836 -236.10824)
		(mid 337.965034 -236.158383)
		(end 338.152232 -236.10824)
		(width 0.0889)
		(layer "B.Cu")
		(net "CLK_100M_DB2000_CPU0_BCLK2_DP")
	)
	(arc
		(start 336.838036 -236.10824)
		(mid 337.025234 -236.158383)
		(end 337.212432 -236.10824)
		(width 0.0889)
		(layer "B.Cu")
		(net "CLK_100M_DB2000_CPU0_BCLK2_DP")
	)
	(arc
		(start 348.490032 -236.10824)
		(mid 348.772734 -236.032498)
		(end 349.055436 -236.10824)
		(width 0.0889)
		(layer "B.Cu")
		(net "CLK_100M_DB2000_CPU0_BCLK2_DP")
	)
	(arc
		(start 335.898236 -236.10824)
		(mid 336.085434 -236.158383)
		(end 336.272632 -236.10824)
		(width 0.0889)
		(layer "B.Cu")
		(net "CLK_100M_DB2000_CPU0_BCLK2_DP")
	)
	(arc
		(start 340.046564 -236.099604)
		(mid 340.323005 -236.032438)
		(end 340.597236 -236.10824)
		(width 0.0889)
		(layer "B.Cu")
		(net "CLK_100M_DB2000_CPU0_BCLK2_DP")
	)
	(arc
		(start 334.871822 -236.91723)
		(mid 335.002736 -236.78087)
		(end 335.050384 -236.597952)
		(width 0.0889)
		(layer "B.Cu")
		(net "CLK_100M_DB2000_CPU0_BCLK2_DP")
	)
	(arc
		(start 339.657436 -236.10824)
		(mid 339.844634 -236.158383)
		(end 340.031832 -236.10824)
		(width 0.0889)
		(layer "B.Cu")
		(net "CLK_100M_DB2000_CPU0_BCLK2_DP")
	)
	(arc
		(start 347.564964 -236.099604)
		(mid 347.841405 -236.032438)
		(end 348.115636 -236.10824)
		(width 0.0889)
		(layer "B.Cu")
		(net "CLK_100M_DB2000_CPU0_BCLK2_DP")
	)
	(arc
		(start 349.444564 -236.099604)
		(mid 349.677479 -236.033423)
		(end 349.91675 -236.070648)
		(width 0.0889)
		(layer "B.Cu")
		(net "CLK_100M_DB2000_CPU0_BCLK2_DP")
	)
	(arc
		(start 335.050384 -236.57941)
		(mid 335.130546 -236.307221)
		(end 335.332832 -236.10824)
		(width 0.0889)
		(layer "B.Cu")
		(net "CLK_100M_DB2000_CPU0_BCLK2_DP")
	)
	(arc
		(start 337.227164 -236.099604)
		(mid 337.503605 -236.032438)
		(end 337.777836 -236.10824)
		(width 0.0889)
		(layer "B.Cu")
		(net "CLK_100M_DB2000_CPU0_BCLK2_DP")
	)
	(arc
		(start 345.680792 -236.102144)
		(mid 345.959224 -236.03233)
		(end 346.236036 -236.10824)
		(width 0.0889)
		(layer "B.Cu")
		(net "CLK_100M_DB2000_CPU0_BCLK2_DP")
	)
	(arc
		(start 343.805764 -236.099604)
		(mid 344.082205 -236.032438)
		(end 344.356436 -236.10824)
		(width 0.0889)
		(layer "B.Cu")
		(net "CLK_100M_DB2000_CPU0_BCLK2_DP")
	)
	(arc
		(start 345.295982 -236.10824)
		(mid 345.48318 -236.158383)
		(end 345.670378 -236.10824)
		(width 0.0889)
		(layer "B.Cu")
		(net "CLK_100M_DB2000_CPU0_BCLK2_DP")
	)
	(arc
		(start 340.597236 -236.10824)
		(mid 340.784434 -236.158383)
		(end 340.971632 -236.10824)
		(width 0.0889)
		(layer "B.Cu")
		(net "CLK_100M_DB2000_CPU0_BCLK2_DP")
	)
	(arc
		(start 346.625164 -236.099604)
		(mid 346.901605 -236.032438)
		(end 347.175836 -236.10824)
		(width 0.0889)
		(layer "B.Cu")
		(net "CLK_100M_DB2000_CPU0_BCLK2_DP")
	)
	(arc
		(start 339.102192 -236.102144)
		(mid 339.380624 -236.03233)
		(end 339.657436 -236.10824)
		(width 0.0889)
		(layer "B.Cu")
		(net "CLK_100M_DB2000_CPU0_BCLK2_DP")
	)
	(arc
		(start 342.865964 -236.099604)
		(mid 343.142405 -236.032438)
		(end 343.416636 -236.10824)
		(width 0.0889)
		(layer "B.Cu")
		(net "CLK_100M_DB2000_CPU0_BCLK2_DP")
	)
	(arc
		(start 334.58023 -237.411768)
		(mid 334.654221 -237.132202)
		(end 334.856836 -236.925866)
		(width 0.0889)
		(layer "B.Cu")
		(net "CLK_100M_DB2000_CPU0_BCLK2_DP")
	)
	(arc
		(start 343.416636 -236.10824)
		(mid 343.603834 -236.158383)
		(end 343.791032 -236.10824)
		(width 0.0889)
		(layer "B.Cu")
		(net "CLK_100M_DB2000_CPU0_BCLK2_DP")
	)
	(arc
		(start 338.717382 -236.10824)
		(mid 338.90458 -236.158383)
		(end 339.091778 -236.10824)
		(width 0.0889)
		(layer "B.Cu")
		(net "CLK_100M_DB2000_CPU0_BCLK2_DP")
	)
	(arc
		(start 344.356436 -236.10824)
		(mid 344.543634 -236.158383)
		(end 344.730832 -236.10824)
		(width 0.0889)
		(layer "B.Cu")
		(net "CLK_100M_DB2000_CPU0_BCLK2_DP")
	)
	(arc
		(start 349.055436 -236.10824)
		(mid 349.242634 -236.158383)
		(end 349.429832 -236.10824)
		(width 0.0889)
		(layer "B.Cu")
		(net "CLK_100M_DB2000_CPU0_BCLK2_DP")
	)
	(arc
		(start 349.91675 -236.070648)
		(mid 349.926823 -236.074614)
		(end 349.936816 -236.078776)
		(width 0.0889)
		(layer "B.Cu")
		(net "CLK_100M_DB2000_CPU0_BCLK2_DP")
	)
	(segment
		(start 245.14048 -135.171688)
		(end 244.83822 -135.473948)
		(width 0.13208)
		(layer "F.Cu")
		(net "CLK_100M_DB2000_CPU0_BCLK2_DN")
	)
	(segment
		(start 349.712534 -236.598206)
		(end 349.71228 -236.597952)
		(width 0.13208)
		(layer "F.Cu")
		(net "CLK_100M_DB2000_CPU0_BCLK2_DN")
	)
	(segment
		(start 349.712534 -237.133892)
		(end 349.712534 -236.598206)
		(width 0.13208)
		(layer "F.Cu")
		(net "CLK_100M_DB2000_CPU0_BCLK2_DN")
	)
	(segment
		(start 238.655098 -132.428488)
		(end 243.23802 -132.428488)
		(width 0.13208)
		(layer "F.Cu")
		(net "CLK_100M_DB2000_CPU0_BCLK2_DN")
	)
	(segment
		(start 236.868462 -129.638298)
		(end 236.868462 -130.641852)
		(width 0.13208)
		(layer "F.Cu")
		(net "CLK_100M_DB2000_CPU0_BCLK2_DN")
	)
	(segment
		(start 243.23802 -132.428488)
		(end 245.14048 -134.330948)
		(width 0.13208)
		(layer "F.Cu")
		(net "CLK_100M_DB2000_CPU0_BCLK2_DN")
	)
	(segment
		(start 245.14048 -134.330948)
		(end 245.14048 -135.171688)
		(width 0.13208)
		(layer "F.Cu")
		(net "CLK_100M_DB2000_CPU0_BCLK2_DN")
	)
	(segment
		(start 236.748066 -129.517902)
		(end 236.868462 -129.638298)
		(width 0.13208)
		(layer "F.Cu")
		(net "CLK_100M_DB2000_CPU0_BCLK2_DN")
	)
	(segment
		(start 236.868462 -130.641852)
		(end 238.655098 -132.428488)
		(width 0.13208)
		(layer "F.Cu")
		(net "CLK_100M_DB2000_CPU0_BCLK2_DN")
	)
	(via
		(at 349.71228 -236.597952)
		(size 0.4572)
		(drill 0.2032)
		(layers "F.Cu" "B.Cu")
		(net "CLK_100M_DB2000_CPU0_BCLK2_DN")
	)
	(via
		(at 244.83822 -135.473948)
		(size 0.508)
		(drill 0.254)
		(layers "F.Cu" "B.Cu")
		(net "CLK_100M_DB2000_CPU0_BCLK2_DN")
	)
	(segment
		(start 244.83822 -135.473948)
		(end 245.14048 -135.776208)
		(width 0.13208)
		(layer "B.Cu")
		(net "CLK_100M_DB2000_CPU0_BCLK2_DN")
	)
	(segment
		(start 334.958182 -237.08741)
		(end 334.958944 -237.086902)
		(width 0.0889)
		(layer "B.Cu")
		(net "CLK_100M_DB2000_CPU0_BCLK2_DN")
	)
	(segment
		(start 298.620688 -185.967878)
		(end 300.441106 -190.362078)
		(width 0.13208)
		(layer "B.Cu")
		(net "CLK_100M_DB2000_CPU0_BCLK2_DN")
	)
	(segment
		(start 346.69095 -236.28223)
		(end 346.705682 -236.273594)
		(width 0.0889)
		(layer "B.Cu")
		(net "CLK_100M_DB2000_CPU0_BCLK2_DN")
	)
	(segment
		(start 340.11235 -236.28223)
		(end 340.127082 -236.273594)
		(width 0.0889)
		(layer "B.Cu")
		(net "CLK_100M_DB2000_CPU0_BCLK2_DN")
	)
	(segment
		(start 275.682202 -180.198776)
		(end 288.95167 -180.198776)
		(width 0.13208)
		(layer "B.Cu")
		(net "CLK_100M_DB2000_CPU0_BCLK2_DN")
	)
	(segment
		(start 273.418046 -179.261008)
		(end 275.682202 -180.198776)
		(width 0.13208)
		(layer "B.Cu")
		(net "CLK_100M_DB2000_CPU0_BCLK2_DN")
	)
	(segment
		(start 303.34712 -199.561196)
		(end 303.34712 -238.409734)
		(width 0.13208)
		(layer "B.Cu")
		(net "CLK_100M_DB2000_CPU0_BCLK2_DN")
	)
	(segment
		(start 343.87155 -236.28223)
		(end 343.886282 -236.273594)
		(width 0.0889)
		(layer "B.Cu")
		(net "CLK_100M_DB2000_CPU0_BCLK2_DN")
	)
	(segment
		(start 288.95167 -180.198776)
		(end 295.609518 -182.956708)
		(width 0.13208)
		(layer "B.Cu")
		(net "CLK_100M_DB2000_CPU0_BCLK2_DN")
	)
	(segment
		(start 335.802986 -236.27334)
		(end 335.802732 -236.273594)
		(width 0.0889)
		(layer "B.Cu")
		(net "CLK_100M_DB2000_CPU0_BCLK2_DN")
	)
	(segment
		(start 334.958944 -237.086902)
		(end 334.964278 -237.083854)
		(width 0.0889)
		(layer "B.Cu")
		(net "CLK_100M_DB2000_CPU0_BCLK2_DN")
	)
	(segment
		(start 306.106068 -240.748058)
		(end 307.732938 -241.422428)
		(width 0.13208)
		(layer "B.Cu")
		(net "CLK_100M_DB2000_CPU0_BCLK2_DN")
	)
	(segment
		(start 312.136282 -240.711228)
		(end 328.14006 -240.711228)
		(width 0.13208)
		(layer "B.Cu")
		(net "CLK_100M_DB2000_CPU0_BCLK2_DN")
	)
	(segment
		(start 310.421274 -241.422428)
		(end 312.136282 -240.711228)
		(width 0.13208)
		(layer "B.Cu")
		(net "CLK_100M_DB2000_CPU0_BCLK2_DN")
	)
	(segment
		(start 341.996522 -236.27969)
		(end 342.006936 -236.273594)
		(width 0.0889)
		(layer "B.Cu")
		(net "CLK_100M_DB2000_CPU0_BCLK2_DN")
	)
	(segment
		(start 303.34712 -238.409734)
		(end 303.929542 -238.99241)
		(width 0.13208)
		(layer "B.Cu")
		(net "CLK_100M_DB2000_CPU0_BCLK2_DN")
	)
	(segment
		(start 328.14006 -240.711228)
		(end 328.91095 -240.39195)
		(width 0.13208)
		(layer "B.Cu")
		(net "CLK_100M_DB2000_CPU0_BCLK2_DN")
	)
	(segment
		(start 341.05215 -236.28223)
		(end 341.066882 -236.273594)
		(width 0.0889)
		(layer "B.Cu")
		(net "CLK_100M_DB2000_CPU0_BCLK2_DN")
	)
	(segment
		(start 331.732382 -238.315246)
		(end 331.75448 -238.315246)
		(width 0.0889)
		(layer "B.Cu")
		(net "CLK_100M_DB2000_CPU0_BCLK2_DN")
	)
	(segment
		(start 295.609518 -182.956708)
		(end 298.620688 -185.967878)
		(width 0.13208)
		(layer "B.Cu")
		(net "CLK_100M_DB2000_CPU0_BCLK2_DN")
	)
	(segment
		(start 331.789024 -238.280702)
		(end 333.980536 -238.280702)
		(width 0.0889)
		(layer "B.Cu")
		(net "CLK_100M_DB2000_CPU0_BCLK2_DN")
	)
	(segment
		(start 338.23275 -236.28223)
		(end 338.247482 -236.273594)
		(width 0.0889)
		(layer "B.Cu")
		(net "CLK_100M_DB2000_CPU0_BCLK2_DN")
	)
	(segment
		(start 333.980536 -238.280702)
		(end 333.98079 -238.280956)
		(width 0.0889)
		(layer "B.Cu")
		(net "CLK_100M_DB2000_CPU0_BCLK2_DN")
	)
	(segment
		(start 349.868744 -236.326934)
		(end 349.71228 -236.597952)
		(width 0.0889)
		(layer "B.Cu")
		(net "CLK_100M_DB2000_CPU0_BCLK2_DN")
	)
	(segment
		(start 349.514668 -236.27969)
		(end 349.525082 -236.273594)
		(width 0.0889)
		(layer "B.Cu")
		(net "CLK_100M_DB2000_CPU0_BCLK2_DN")
	)
	(segment
		(start 300.441106 -190.362078)
		(end 300.603666 -190.60541)
		(width 0.13208)
		(layer "B.Cu")
		(net "CLK_100M_DB2000_CPU0_BCLK2_DN")
	)
	(segment
		(start 245.14048 -135.776208)
		(end 245.14048 -136.928352)
		(width 0.13208)
		(layer "B.Cu")
		(net "CLK_100M_DB2000_CPU0_BCLK2_DN")
	)
	(segment
		(start 334.770984 -237.411768)
		(end 334.770984 -237.403132)
		(width 0.0889)
		(layer "B.Cu")
		(net "CLK_100M_DB2000_CPU0_BCLK2_DN")
	)
	(segment
		(start 253.435104 -159.278066)
		(end 273.418046 -179.261008)
		(width 0.13208)
		(layer "B.Cu")
		(net "CLK_100M_DB2000_CPU0_BCLK2_DN")
	)
	(segment
		(start 335.516728 -236.223048)
		(end 335.615534 -236.223048)
		(width 0.0889)
		(layer "B.Cu")
		(net "CLK_100M_DB2000_CPU0_BCLK2_DN")
	)
	(segment
		(start 347.63075 -236.28223)
		(end 347.645482 -236.273594)
		(width 0.0889)
		(layer "B.Cu")
		(net "CLK_100M_DB2000_CPU0_BCLK2_DN")
	)
	(segment
		(start 348.575122 -236.27969)
		(end 348.585536 -236.273594)
		(width 0.0889)
		(layer "B.Cu")
		(net "CLK_100M_DB2000_CPU0_BCLK2_DN")
	)
	(segment
		(start 301.74184 -197.523608)
		(end 301.842678 -197.766432)
		(width 0.13208)
		(layer "B.Cu")
		(net "CLK_100M_DB2000_CPU0_BCLK2_DN")
	)
	(segment
		(start 305.197256 -239.8395)
		(end 306.106068 -240.748058)
		(width 0.13208)
		(layer "B.Cu")
		(net "CLK_100M_DB2000_CPU0_BCLK2_DN")
	)
	(segment
		(start 301.842678 -197.766432)
		(end 303.141634 -199.065896)
		(width 0.13208)
		(layer "B.Cu")
		(net "CLK_100M_DB2000_CPU0_BCLK2_DN")
	)
	(segment
		(start 245.14048 -136.928352)
		(end 246.030242 -141.401038)
		(width 0.13208)
		(layer "B.Cu")
		(net "CLK_100M_DB2000_CPU0_BCLK2_DN")
	)
	(segment
		(start 344.81135 -236.28223)
		(end 344.826082 -236.273594)
		(width 0.0889)
		(layer "B.Cu")
		(net "CLK_100M_DB2000_CPU0_BCLK2_DN")
	)
	(segment
		(start 307.732938 -241.422428)
		(end 310.421274 -241.422428)
		(width 0.13208)
		(layer "B.Cu")
		(net "CLK_100M_DB2000_CPU0_BCLK2_DN")
	)
	(segment
		(start 342.936068 -236.27969)
		(end 342.946482 -236.273594)
		(width 0.0889)
		(layer "B.Cu")
		(net "CLK_100M_DB2000_CPU0_BCLK2_DN")
	)
	(segment
		(start 349.847662 -236.248956)
		(end 349.868744 -236.326934)
		(width 0.0889)
		(layer "B.Cu")
		(net "CLK_100M_DB2000_CPU0_BCLK2_DN")
	)
	(segment
		(start 328.91095 -240.39195)
		(end 330.987654 -238.315246)
		(width 0.13208)
		(layer "B.Cu")
		(net "CLK_100M_DB2000_CPU0_BCLK2_DN")
	)
	(segment
		(start 301.74184 -193.35369)
		(end 301.74184 -197.523608)
		(width 0.13208)
		(layer "B.Cu")
		(net "CLK_100M_DB2000_CPU0_BCLK2_DN")
	)
	(segment
		(start 333.98079 -238.280956)
		(end 334.291432 -237.970568)
		(width 0.0889)
		(layer "B.Cu")
		(net "CLK_100M_DB2000_CPU0_BCLK2_DN")
	)
	(segment
		(start 335.419446 -236.278674)
		(end 335.516728 -236.223048)
		(width 0.0889)
		(layer "B.Cu")
		(net "CLK_100M_DB2000_CPU0_BCLK2_DN")
	)
	(segment
		(start 331.75448 -238.315246)
		(end 331.789024 -238.280702)
		(width 0.0889)
		(layer "B.Cu")
		(net "CLK_100M_DB2000_CPU0_BCLK2_DN")
	)
	(segment
		(start 303.929542 -238.99241)
		(end 305.197256 -239.8395)
		(width 0.13208)
		(layer "B.Cu")
		(net "CLK_100M_DB2000_CPU0_BCLK2_DN")
	)
	(segment
		(start 300.603666 -190.60541)
		(end 301.74184 -193.35369)
		(width 0.13208)
		(layer "B.Cu")
		(net "CLK_100M_DB2000_CPU0_BCLK2_DN")
	)
	(segment
		(start 303.141634 -199.065896)
		(end 303.34712 -199.561196)
		(width 0.13208)
		(layer "B.Cu")
		(net "CLK_100M_DB2000_CPU0_BCLK2_DN")
	)
	(segment
		(start 337.297268 -236.27969)
		(end 337.307682 -236.273594)
		(width 0.0889)
		(layer "B.Cu")
		(net "CLK_100M_DB2000_CPU0_BCLK2_DN")
	)
	(segment
		(start 330.987654 -238.315246)
		(end 331.732382 -238.315246)
		(width 0.13208)
		(layer "B.Cu")
		(net "CLK_100M_DB2000_CPU0_BCLK2_DN")
	)
	(segment
		(start 246.030242 -141.401038)
		(end 253.435104 -159.278066)
		(width 0.13208)
		(layer "B.Cu")
		(net "CLK_100M_DB2000_CPU0_BCLK2_DN")
	)
	(arc
		(start 349.525082 -236.273594)
		(mid 349.68357 -236.224661)
		(end 349.847662 -236.248956)
		(width 0.0889)
		(layer "B.Cu")
		(net "CLK_100M_DB2000_CPU0_BCLK2_DN")
	)
	(arc
		(start 347.645482 -236.273594)
		(mid 347.83268 -236.223451)
		(end 348.019878 -236.273594)
		(width 0.0889)
		(layer "B.Cu")
		(net "CLK_100M_DB2000_CPU0_BCLK2_DN")
	)
	(arc
		(start 343.320878 -236.273594)
		(mid 343.595107 -236.349519)
		(end 343.87155 -236.28223)
		(width 0.0889)
		(layer "B.Cu")
		(net "CLK_100M_DB2000_CPU0_BCLK2_DN")
	)
	(arc
		(start 344.826082 -236.273594)
		(mid 345.01328 -236.223451)
		(end 345.200478 -236.273594)
		(width 0.0889)
		(layer "B.Cu")
		(net "CLK_100M_DB2000_CPU0_BCLK2_DN")
	)
	(arc
		(start 336.368136 -236.273594)
		(mid 336.555334 -236.223451)
		(end 336.742532 -236.273594)
		(width 0.0889)
		(layer "B.Cu")
		(net "CLK_100M_DB2000_CPU0_BCLK2_DN")
	)
	(arc
		(start 344.260678 -236.273594)
		(mid 344.534907 -236.349519)
		(end 344.81135 -236.28223)
		(width 0.0889)
		(layer "B.Cu")
		(net "CLK_100M_DB2000_CPU0_BCLK2_DN")
	)
	(arc
		(start 334.964278 -237.083854)
		(mid 335.166865 -236.877503)
		(end 335.240884 -236.597952)
		(width 0.0889)
		(layer "B.Cu")
		(net "CLK_100M_DB2000_CPU0_BCLK2_DN")
	)
	(arc
		(start 341.441278 -236.273594)
		(mid 341.718091 -236.34943)
		(end 341.996522 -236.27969)
		(width 0.0889)
		(layer "B.Cu")
		(net "CLK_100M_DB2000_CPU0_BCLK2_DN")
	)
	(arc
		(start 342.381332 -236.273594)
		(mid 342.657891 -236.349303)
		(end 342.936068 -236.27969)
		(width 0.0889)
		(layer "B.Cu")
		(net "CLK_100M_DB2000_CPU0_BCLK2_DN")
	)
	(arc
		(start 343.886282 -236.273594)
		(mid 344.07348 -236.223451)
		(end 344.260678 -236.273594)
		(width 0.0889)
		(layer "B.Cu")
		(net "CLK_100M_DB2000_CPU0_BCLK2_DN")
	)
	(arc
		(start 346.140278 -236.273594)
		(mid 346.414507 -236.349519)
		(end 346.69095 -236.28223)
		(width 0.0889)
		(layer "B.Cu")
		(net "CLK_100M_DB2000_CPU0_BCLK2_DN")
	)
	(arc
		(start 347.080078 -236.273594)
		(mid 347.354307 -236.349519)
		(end 347.63075 -236.28223)
		(width 0.0889)
		(layer "B.Cu")
		(net "CLK_100M_DB2000_CPU0_BCLK2_DN")
	)
	(arc
		(start 340.501478 -236.273594)
		(mid 340.775707 -236.349519)
		(end 341.05215 -236.28223)
		(width 0.0889)
		(layer "B.Cu")
		(net "CLK_100M_DB2000_CPU0_BCLK2_DN")
	)
	(arc
		(start 334.770984 -237.403132)
		(mid 334.823254 -237.220767)
		(end 334.958182 -237.08741)
		(width 0.0889)
		(layer "B.Cu")
		(net "CLK_100M_DB2000_CPU0_BCLK2_DN")
	)
	(arc
		(start 335.615534 -236.223048)
		(mid 335.712582 -236.235827)
		(end 335.802986 -236.27334)
		(width 0.0889)
		(layer "B.Cu")
		(net "CLK_100M_DB2000_CPU0_BCLK2_DN")
	)
	(arc
		(start 335.240884 -236.597952)
		(mid 335.288563 -236.415052)
		(end 335.419446 -236.278674)
		(width 0.0889)
		(layer "B.Cu")
		(net "CLK_100M_DB2000_CPU0_BCLK2_DN")
	)
	(arc
		(start 348.959932 -236.273594)
		(mid 349.236491 -236.349303)
		(end 349.514668 -236.27969)
		(width 0.0889)
		(layer "B.Cu")
		(net "CLK_100M_DB2000_CPU0_BCLK2_DN")
	)
	(arc
		(start 338.621878 -236.273594)
		(mid 338.90458 -236.349336)
		(end 339.187282 -236.273594)
		(width 0.0889)
		(layer "B.Cu")
		(net "CLK_100M_DB2000_CPU0_BCLK2_DN")
	)
	(arc
		(start 345.200478 -236.273594)
		(mid 345.48318 -236.349336)
		(end 345.765882 -236.273594)
		(width 0.0889)
		(layer "B.Cu")
		(net "CLK_100M_DB2000_CPU0_BCLK2_DN")
	)
	(arc
		(start 340.127082 -236.273594)
		(mid 340.31428 -236.223451)
		(end 340.501478 -236.273594)
		(width 0.0889)
		(layer "B.Cu")
		(net "CLK_100M_DB2000_CPU0_BCLK2_DN")
	)
	(arc
		(start 337.307682 -236.273594)
		(mid 337.49488 -236.223451)
		(end 337.682078 -236.273594)
		(width 0.0889)
		(layer "B.Cu")
		(net "CLK_100M_DB2000_CPU0_BCLK2_DN")
	)
	(arc
		(start 339.187282 -236.273594)
		(mid 339.37448 -236.223451)
		(end 339.561678 -236.273594)
		(width 0.0889)
		(layer "B.Cu")
		(net "CLK_100M_DB2000_CPU0_BCLK2_DN")
	)
	(arc
		(start 339.561678 -236.273594)
		(mid 339.835907 -236.349519)
		(end 340.11235 -236.28223)
		(width 0.0889)
		(layer "B.Cu")
		(net "CLK_100M_DB2000_CPU0_BCLK2_DN")
	)
	(arc
		(start 346.705682 -236.273594)
		(mid 346.89288 -236.223451)
		(end 347.080078 -236.273594)
		(width 0.0889)
		(layer "B.Cu")
		(net "CLK_100M_DB2000_CPU0_BCLK2_DN")
	)
	(arc
		(start 338.247482 -236.273594)
		(mid 338.43468 -236.223451)
		(end 338.621878 -236.273594)
		(width 0.0889)
		(layer "B.Cu")
		(net "CLK_100M_DB2000_CPU0_BCLK2_DN")
	)
	(arc
		(start 342.946482 -236.273594)
		(mid 343.13368 -236.223451)
		(end 343.320878 -236.273594)
		(width 0.0889)
		(layer "B.Cu")
		(net "CLK_100M_DB2000_CPU0_BCLK2_DN")
	)
	(arc
		(start 334.291432 -237.970568)
		(mid 334.634628 -237.779933)
		(end 334.770984 -237.411768)
		(width 0.0889)
		(layer "B.Cu")
		(net "CLK_100M_DB2000_CPU0_BCLK2_DN")
	)
	(arc
		(start 342.006936 -236.273594)
		(mid 342.194134 -236.223451)
		(end 342.381332 -236.273594)
		(width 0.0889)
		(layer "B.Cu")
		(net "CLK_100M_DB2000_CPU0_BCLK2_DN")
	)
	(arc
		(start 336.742532 -236.273594)
		(mid 337.019091 -236.349303)
		(end 337.297268 -236.27969)
		(width 0.0889)
		(layer "B.Cu")
		(net "CLK_100M_DB2000_CPU0_BCLK2_DN")
	)
	(arc
		(start 345.765882 -236.273594)
		(mid 345.95308 -236.223451)
		(end 346.140278 -236.273594)
		(width 0.0889)
		(layer "B.Cu")
		(net "CLK_100M_DB2000_CPU0_BCLK2_DN")
	)
	(arc
		(start 337.682078 -236.273594)
		(mid 337.956307 -236.349519)
		(end 338.23275 -236.28223)
		(width 0.0889)
		(layer "B.Cu")
		(net "CLK_100M_DB2000_CPU0_BCLK2_DN")
	)
	(arc
		(start 348.585536 -236.273594)
		(mid 348.772734 -236.223451)
		(end 348.959932 -236.273594)
		(width 0.0889)
		(layer "B.Cu")
		(net "CLK_100M_DB2000_CPU0_BCLK2_DN")
	)
	(arc
		(start 341.066882 -236.273594)
		(mid 341.25408 -236.223451)
		(end 341.441278 -236.273594)
		(width 0.0889)
		(layer "B.Cu")
		(net "CLK_100M_DB2000_CPU0_BCLK2_DN")
	)
	(arc
		(start 348.019878 -236.273594)
		(mid 348.296691 -236.34943)
		(end 348.575122 -236.27969)
		(width 0.0889)
		(layer "B.Cu")
		(net "CLK_100M_DB2000_CPU0_BCLK2_DN")
	)
	(arc
		(start 335.802732 -236.273594)
		(mid 336.085434 -236.349336)
		(end 336.368136 -236.273594)
		(width 0.0889)
		(layer "B.Cu")
		(net "CLK_100M_DB2000_CPU0_BCLK2_DN")
	)
	(segment
		(start 369.448334 -237.133892)
		(end 369.448588 -237.133638)
		(width 0.13208)
		(layer "F.Cu")
		(net "CLK_100M_DB2000_CPU0_BCLK1_DP")
	)
	(segment
		(start 237.748064 -129.017776)
		(end 237.86846 -129.138172)
		(width 0.13208)
		(layer "F.Cu")
		(net "CLK_100M_DB2000_CPU0_BCLK1_DP")
	)
	(segment
		(start 369.448588 -237.133638)
		(end 369.448588 -236.597952)
		(width 0.13208)
		(layer "F.Cu")
		(net "CLK_100M_DB2000_CPU0_BCLK1_DP")
	)
	(segment
		(start 241.25936 -130.160268)
		(end 242.12042 -130.160268)
		(width 0.13208)
		(layer "F.Cu")
		(net "CLK_100M_DB2000_CPU0_BCLK1_DP")
	)
	(segment
		(start 242.12042 -130.160268)
		(end 242.42268 -129.858008)
		(width 0.13208)
		(layer "F.Cu")
		(net "CLK_100M_DB2000_CPU0_BCLK1_DP")
	)
	(segment
		(start 237.86846 -129.138172)
		(end 238.150146 -129.138172)
		(width 0.13208)
		(layer "F.Cu")
		(net "CLK_100M_DB2000_CPU0_BCLK1_DP")
	)
	(segment
		(start 239.385602 -129.384044)
		(end 241.25936 -130.160268)
		(width 0.13208)
		(layer "F.Cu")
		(net "CLK_100M_DB2000_CPU0_BCLK1_DP")
	)
	(segment
		(start 238.150146 -129.138172)
		(end 239.385602 -129.384044)
		(width 0.13208)
		(layer "F.Cu")
		(net "CLK_100M_DB2000_CPU0_BCLK1_DP")
	)
	(via
		(at 369.448588 -236.597952)
		(size 0.4572)
		(drill 0.2032)
		(layers "F.Cu" "B.Cu")
		(net "CLK_100M_DB2000_CPU0_BCLK1_DP")
	)
	(via
		(at 242.42268 -129.858008)
		(size 0.508)
		(drill 0.254)
		(layers "F.Cu" "B.Cu")
		(net "CLK_100M_DB2000_CPU0_BCLK1_DP")
	)
	(segment
		(start 369.822984 -236.613446)
		(end 369.822984 -236.589316)
		(width 0.0889)
		(layer "B.Cu")
		(net "CLK_100M_DB2000_CPU0_BCLK1_DP")
	)
	(segment
		(start 344.428064 -154.155902)
		(end 350.794066 -158.381446)
		(width 0.13208)
		(layer "B.Cu")
		(net "CLK_100M_DB2000_CPU0_BCLK1_DP")
	)
	(segment
		(start 374.899682 -237.901226)
		(end 374.889268 -237.907322)
		(width 0.0889)
		(layer "B.Cu")
		(net "CLK_100M_DB2000_CPU0_BCLK1_DP")
	)
	(segment
		(start 377.719082 -237.901226)
		(end 377.70435 -237.909862)
		(width 0.0889)
		(layer "B.Cu")
		(net "CLK_100M_DB2000_CPU0_BCLK1_DP")
	)
	(segment
		(start 371.140482 -237.901226)
		(end 371.12575 -237.909862)
		(width 0.0889)
		(layer "B.Cu")
		(net "CLK_100M_DB2000_CPU0_BCLK1_DP")
	)
	(segment
		(start 373.020082 -237.901226)
		(end 373.00535 -237.909862)
		(width 0.0889)
		(layer "B.Cu")
		(net "CLK_100M_DB2000_CPU0_BCLK1_DP")
	)
	(segment
		(start 370.485162 -168.13149)
		(end 371.655848 -168.13149)
		(width 0.13208)
		(layer "B.Cu")
		(net "CLK_100M_DB2000_CPU0_BCLK1_DP")
	)
	(segment
		(start 246.988584 -131.519422)
		(end 252.30836 -132.57784)
		(width 0.13208)
		(layer "B.Cu")
		(net "CLK_100M_DB2000_CPU0_BCLK1_DP")
	)
	(segment
		(start 350.794066 -158.381446)
		(end 350.794066 -158.381192)
		(width 0.13208)
		(layer "B.Cu")
		(net "CLK_100M_DB2000_CPU0_BCLK1_DP")
	)
	(segment
		(start 362.130086 -164.629846)
		(end 367.181638 -167.076374)
		(width 0.13208)
		(layer "B.Cu")
		(net "CLK_100M_DB2000_CPU0_BCLK1_DP")
	)
	(segment
		(start 370.292884 -237.433612)
		(end 370.292884 -237.411514)
		(width 0.0889)
		(layer "B.Cu")
		(net "CLK_100M_DB2000_CPU0_BCLK1_DP")
	)
	(segment
		(start 243.706142 -130.160268)
		(end 246.988584 -131.519422)
		(width 0.13208)
		(layer "B.Cu")
		(net "CLK_100M_DB2000_CPU0_BCLK1_DP")
	)
	(segment
		(start 375.806716 -170.494198)
		(end 379.041406 -175.335946)
		(width 0.13208)
		(layer "B.Cu")
		(net "CLK_100M_DB2000_CPU0_BCLK1_DP")
	)
	(segment
		(start 389.17626 -185.471054)
		(end 392.285982 -192.978024)
		(width 0.13208)
		(layer "B.Cu")
		(net "CLK_100M_DB2000_CPU0_BCLK1_DP")
	)
	(segment
		(start 372.080282 -237.901226)
		(end 372.06555 -237.909862)
		(width 0.0889)
		(layer "B.Cu")
		(net "CLK_100M_DB2000_CPU0_BCLK1_DP")
	)
	(segment
		(start 341.651844 -151.379936)
		(end 344.428064 -154.155902)
		(width 0.13208)
		(layer "B.Cu")
		(net "CLK_100M_DB2000_CPU0_BCLK1_DP")
	)
	(segment
		(start 367.181638 -167.076374)
		(end 369.032028 -167.842184)
		(width 0.13208)
		(layer "B.Cu")
		(net "CLK_100M_DB2000_CPU0_BCLK1_DP")
	)
	(segment
		(start 242.42268 -129.858008)
		(end 242.72494 -130.160268)
		(width 0.13208)
		(layer "B.Cu")
		(net "CLK_100M_DB2000_CPU0_BCLK1_DP")
	)
	(segment
		(start 397.28648 -228.894894)
		(end 397.020288 -229.537514)
		(width 0.13208)
		(layer "B.Cu")
		(net "CLK_100M_DB2000_CPU0_BCLK1_DP")
	)
	(segment
		(start 242.72494 -130.160268)
		(end 243.706142 -130.160268)
		(width 0.13208)
		(layer "B.Cu")
		(net "CLK_100M_DB2000_CPU0_BCLK1_DP")
	)
	(segment
		(start 369.605052 -236.326934)
		(end 369.448588 -236.597952)
		(width 0.0889)
		(layer "B.Cu")
		(net "CLK_100M_DB2000_CPU0_BCLK1_DP")
	)
	(segment
		(start 392.285982 -192.978024)
		(end 397.28648 -197.978522)
		(width 0.13208)
		(layer "B.Cu")
		(net "CLK_100M_DB2000_CPU0_BCLK1_DP")
	)
	(segment
		(start 379.041406 -175.335946)
		(end 389.17626 -185.471054)
		(width 0.13208)
		(layer "B.Cu")
		(net "CLK_100M_DB2000_CPU0_BCLK1_DP")
	)
	(segment
		(start 380.927864 -237.909862)
		(end 380.913132 -237.901226)
		(width 0.0889)
		(layer "B.Cu")
		(net "CLK_100M_DB2000_CPU0_BCLK1_DP")
	)
	(segment
		(start 397.020288 -229.537514)
		(end 390.463532 -236.09427)
		(width 0.13208)
		(layer "B.Cu")
		(net "CLK_100M_DB2000_CPU0_BCLK1_DP")
	)
	(segment
		(start 252.30836 -132.57784)
		(end 266.68476 -133.99389)
		(width 0.13208)
		(layer "B.Cu")
		(net "CLK_100M_DB2000_CPU0_BCLK1_DP")
	)
	(segment
		(start 266.68476 -133.99389)
		(end 306.37861 -141.88948)
		(width 0.13208)
		(layer "B.Cu")
		(net "CLK_100M_DB2000_CPU0_BCLK1_DP")
	)
	(segment
		(start 380.538736 -237.901226)
		(end 380.528322 -237.907322)
		(width 0.0889)
		(layer "B.Cu")
		(net "CLK_100M_DB2000_CPU0_BCLK1_DP")
	)
	(segment
		(start 306.37861 -141.88948)
		(end 318.740282 -141.88948)
		(width 0.13208)
		(layer "B.Cu")
		(net "CLK_100M_DB2000_CPU0_BCLK1_DP")
	)
	(segment
		(start 376.779282 -237.901226)
		(end 376.76455 -237.909862)
		(width 0.0889)
		(layer "B.Cu")
		(net "CLK_100M_DB2000_CPU0_BCLK1_DP")
	)
	(segment
		(start 385.624578 -237.370112)
		(end 385.60248 -237.370112)
		(width 0.0889)
		(layer "B.Cu")
		(net "CLK_100M_DB2000_CPU0_BCLK1_DP")
	)
	(segment
		(start 318.740282 -141.88948)
		(end 341.651844 -151.379936)
		(width 0.13208)
		(layer "B.Cu")
		(net "CLK_100M_DB2000_CPU0_BCLK1_DP")
	)
	(segment
		(start 350.794066 -158.381192)
		(end 357.159814 -162.606482)
		(width 0.13208)
		(layer "B.Cu")
		(net "CLK_100M_DB2000_CPU0_BCLK1_DP")
	)
	(segment
		(start 385.56819 -237.335822)
		(end 383.950718 -237.335822)
		(width 0.0889)
		(layer "B.Cu")
		(net "CLK_100M_DB2000_CPU0_BCLK1_DP")
	)
	(segment
		(start 379.598682 -237.901226)
		(end 379.58395 -237.909862)
		(width 0.0889)
		(layer "B.Cu")
		(net "CLK_100M_DB2000_CPU0_BCLK1_DP")
	)
	(segment
		(start 370.119656 -237.095538)
		(end 370.105432 -237.08741)
		(width 0.0889)
		(layer "B.Cu")
		(net "CLK_100M_DB2000_CPU0_BCLK1_DP")
	)
	(segment
		(start 369.68303 -236.306106)
		(end 369.605052 -236.326934)
		(width 0.0889)
		(layer "B.Cu")
		(net "CLK_100M_DB2000_CPU0_BCLK1_DP")
	)
	(segment
		(start 387.386322 -237.369096)
		(end 385.83108 -237.369096)
		(width 0.13208)
		(layer "B.Cu")
		(net "CLK_100M_DB2000_CPU0_BCLK1_DP")
	)
	(segment
		(start 385.830064 -237.370112)
		(end 385.624578 -237.370112)
		(width 0.13208)
		(layer "B.Cu")
		(net "CLK_100M_DB2000_CPU0_BCLK1_DP")
	)
	(segment
		(start 383.47523 -237.81131)
		(end 383.474976 -237.811818)
		(width 0.0889)
		(layer "B.Cu")
		(net "CLK_100M_DB2000_CPU0_BCLK1_DP")
	)
	(segment
		(start 397.28648 -197.978522)
		(end 397.28648 -228.894894)
		(width 0.13208)
		(layer "B.Cu")
		(net "CLK_100M_DB2000_CPU0_BCLK1_DP")
	)
	(segment
		(start 385.60248 -237.370112)
		(end 385.56819 -237.335822)
		(width 0.0889)
		(layer "B.Cu")
		(net "CLK_100M_DB2000_CPU0_BCLK1_DP")
	)
	(segment
		(start 375.839482 -237.901226)
		(end 375.82475 -237.909862)
		(width 0.0889)
		(layer "B.Cu")
		(net "CLK_100M_DB2000_CPU0_BCLK1_DP")
	)
	(segment
		(start 385.83108 -237.369096)
		(end 385.830064 -237.370112)
		(width 0.13208)
		(layer "B.Cu")
		(net "CLK_100M_DB2000_CPU0_BCLK1_DP")
	)
	(segment
		(start 383.950718 -237.335822)
		(end 383.47523 -237.81131)
		(width 0.0889)
		(layer "B.Cu")
		(net "CLK_100M_DB2000_CPU0_BCLK1_DP")
	)
	(segment
		(start 369.032028 -167.842184)
		(end 370.485162 -168.13149)
		(width 0.13208)
		(layer "B.Cu")
		(net "CLK_100M_DB2000_CPU0_BCLK1_DP")
	)
	(segment
		(start 373.960136 -237.901226)
		(end 373.949722 -237.907322)
		(width 0.0889)
		(layer "B.Cu")
		(net "CLK_100M_DB2000_CPU0_BCLK1_DP")
	)
	(segment
		(start 372.781576 -168.472866)
		(end 375.806716 -170.494198)
		(width 0.13208)
		(layer "B.Cu")
		(net "CLK_100M_DB2000_CPU0_BCLK1_DP")
	)
	(segment
		(start 371.655848 -168.13149)
		(end 372.781576 -168.472866)
		(width 0.13208)
		(layer "B.Cu")
		(net "CLK_100M_DB2000_CPU0_BCLK1_DP")
	)
	(segment
		(start 378.658882 -237.901226)
		(end 378.64415 -237.909862)
		(width 0.0889)
		(layer "B.Cu")
		(net "CLK_100M_DB2000_CPU0_BCLK1_DP")
	)
	(segment
		(start 390.463532 -236.09427)
		(end 387.386322 -237.369096)
		(width 0.13208)
		(layer "B.Cu")
		(net "CLK_100M_DB2000_CPU0_BCLK1_DP")
	)
	(segment
		(start 357.159814 -162.606482)
		(end 362.130086 -164.629846)
		(width 0.13208)
		(layer "B.Cu")
		(net "CLK_100M_DB2000_CPU0_BCLK1_DP")
	)
	(arc
		(start 373.949722 -237.907322)
		(mid 373.67129 -237.977136)
		(end 373.394478 -237.901226)
		(width 0.0889)
		(layer "B.Cu")
		(net "CLK_100M_DB2000_CPU0_BCLK1_DP")
	)
	(arc
		(start 372.454678 -237.901226)
		(mid 372.26748 -237.851083)
		(end 372.080282 -237.901226)
		(width 0.0889)
		(layer "B.Cu")
		(net "CLK_100M_DB2000_CPU0_BCLK1_DP")
	)
	(arc
		(start 374.889268 -237.907322)
		(mid 374.61109 -237.977014)
		(end 374.334532 -237.901226)
		(width 0.0889)
		(layer "B.Cu")
		(net "CLK_100M_DB2000_CPU0_BCLK1_DP")
	)
	(arc
		(start 380.528322 -237.907322)
		(mid 380.24989 -237.977136)
		(end 379.973078 -237.901226)
		(width 0.0889)
		(layer "B.Cu")
		(net "CLK_100M_DB2000_CPU0_BCLK1_DP")
	)
	(arc
		(start 373.394478 -237.901226)
		(mid 373.20728 -237.851083)
		(end 373.020082 -237.901226)
		(width 0.0889)
		(layer "B.Cu")
		(net "CLK_100M_DB2000_CPU0_BCLK1_DP")
	)
	(arc
		(start 383.358136 -237.901226)
		(mid 383.075434 -237.977002)
		(end 382.792732 -237.901226)
		(width 0.0889)
		(layer "B.Cu")
		(net "CLK_100M_DB2000_CPU0_BCLK1_DP")
	)
	(arc
		(start 382.418336 -237.901226)
		(mid 382.135634 -237.976968)
		(end 381.852932 -237.901226)
		(width 0.0889)
		(layer "B.Cu")
		(net "CLK_100M_DB2000_CPU0_BCLK1_DP")
	)
	(arc
		(start 379.973078 -237.901226)
		(mid 379.78588 -237.851083)
		(end 379.598682 -237.901226)
		(width 0.0889)
		(layer "B.Cu")
		(net "CLK_100M_DB2000_CPU0_BCLK1_DP")
	)
	(arc
		(start 377.70435 -237.909862)
		(mid 377.427909 -237.977028)
		(end 377.153678 -237.901226)
		(width 0.0889)
		(layer "B.Cu")
		(net "CLK_100M_DB2000_CPU0_BCLK1_DP")
	)
	(arc
		(start 380.913132 -237.901226)
		(mid 380.725934 -237.851083)
		(end 380.538736 -237.901226)
		(width 0.0889)
		(layer "B.Cu")
		(net "CLK_100M_DB2000_CPU0_BCLK1_DP")
	)
	(arc
		(start 383.474976 -237.811818)
		(mid 383.463075 -237.823296)
		(end 383.450846 -237.834424)
		(width 0.0889)
		(layer "B.Cu")
		(net "CLK_100M_DB2000_CPU0_BCLK1_DP")
	)
	(arc
		(start 371.12575 -237.909862)
		(mid 370.577254 -237.90262)
		(end 370.292884 -237.433612)
		(width 0.0889)
		(layer "B.Cu")
		(net "CLK_100M_DB2000_CPU0_BCLK1_DP")
	)
	(arc
		(start 378.64415 -237.909862)
		(mid 378.367709 -237.977028)
		(end 378.093478 -237.901226)
		(width 0.0889)
		(layer "B.Cu")
		(net "CLK_100M_DB2000_CPU0_BCLK1_DP")
	)
	(arc
		(start 376.213878 -237.901226)
		(mid 376.02668 -237.851083)
		(end 375.839482 -237.901226)
		(width 0.0889)
		(layer "B.Cu")
		(net "CLK_100M_DB2000_CPU0_BCLK1_DP")
	)
	(arc
		(start 378.093478 -237.901226)
		(mid 377.90628 -237.851083)
		(end 377.719082 -237.901226)
		(width 0.0889)
		(layer "B.Cu")
		(net "CLK_100M_DB2000_CPU0_BCLK1_DP")
	)
	(arc
		(start 372.06555 -237.909862)
		(mid 371.789109 -237.977028)
		(end 371.514878 -237.901226)
		(width 0.0889)
		(layer "B.Cu")
		(net "CLK_100M_DB2000_CPU0_BCLK1_DP")
	)
	(arc
		(start 383.450846 -237.834424)
		(mid 383.406184 -237.870174)
		(end 383.358136 -237.901226)
		(width 0.0889)
		(layer "B.Cu")
		(net "CLK_100M_DB2000_CPU0_BCLK1_DP")
	)
	(arc
		(start 381.852932 -237.901226)
		(mid 381.665734 -237.851083)
		(end 381.478536 -237.901226)
		(width 0.0889)
		(layer "B.Cu")
		(net "CLK_100M_DB2000_CPU0_BCLK1_DP")
	)
	(arc
		(start 381.478536 -237.901226)
		(mid 381.204307 -237.977151)
		(end 380.927864 -237.909862)
		(width 0.0889)
		(layer "B.Cu")
		(net "CLK_100M_DB2000_CPU0_BCLK1_DP")
	)
	(arc
		(start 369.822984 -236.589316)
		(mid 369.78431 -236.432248)
		(end 369.68303 -236.306106)
		(width 0.0889)
		(layer "B.Cu")
		(net "CLK_100M_DB2000_CPU0_BCLK1_DP")
	)
	(arc
		(start 376.76455 -237.909862)
		(mid 376.488109 -237.977028)
		(end 376.213878 -237.901226)
		(width 0.0889)
		(layer "B.Cu")
		(net "CLK_100M_DB2000_CPU0_BCLK1_DP")
	)
	(arc
		(start 370.105432 -237.08741)
		(mid 369.902434 -236.887241)
		(end 369.822984 -236.613446)
		(width 0.0889)
		(layer "B.Cu")
		(net "CLK_100M_DB2000_CPU0_BCLK1_DP")
	)
	(arc
		(start 371.514878 -237.901226)
		(mid 371.32768 -237.851083)
		(end 371.140482 -237.901226)
		(width 0.0889)
		(layer "B.Cu")
		(net "CLK_100M_DB2000_CPU0_BCLK1_DP")
	)
	(arc
		(start 375.82475 -237.909862)
		(mid 375.548309 -237.977028)
		(end 375.274078 -237.901226)
		(width 0.0889)
		(layer "B.Cu")
		(net "CLK_100M_DB2000_CPU0_BCLK1_DP")
	)
	(arc
		(start 374.334532 -237.901226)
		(mid 374.147334 -237.851083)
		(end 373.960136 -237.901226)
		(width 0.0889)
		(layer "B.Cu")
		(net "CLK_100M_DB2000_CPU0_BCLK1_DP")
	)
	(arc
		(start 377.153678 -237.901226)
		(mid 376.96648 -237.851083)
		(end 376.779282 -237.901226)
		(width 0.0889)
		(layer "B.Cu")
		(net "CLK_100M_DB2000_CPU0_BCLK1_DP")
	)
	(arc
		(start 379.58395 -237.909862)
		(mid 379.307509 -237.977028)
		(end 379.033278 -237.901226)
		(width 0.0889)
		(layer "B.Cu")
		(net "CLK_100M_DB2000_CPU0_BCLK1_DP")
	)
	(arc
		(start 379.033278 -237.901226)
		(mid 378.84608 -237.851083)
		(end 378.658882 -237.901226)
		(width 0.0889)
		(layer "B.Cu")
		(net "CLK_100M_DB2000_CPU0_BCLK1_DP")
	)
	(arc
		(start 370.292884 -237.411514)
		(mid 370.246745 -237.231329)
		(end 370.119656 -237.095538)
		(width 0.0889)
		(layer "B.Cu")
		(net "CLK_100M_DB2000_CPU0_BCLK1_DP")
	)
	(arc
		(start 373.00535 -237.909862)
		(mid 372.728909 -237.977028)
		(end 372.454678 -237.901226)
		(width 0.0889)
		(layer "B.Cu")
		(net "CLK_100M_DB2000_CPU0_BCLK1_DP")
	)
	(arc
		(start 382.792732 -237.901226)
		(mid 382.605534 -237.851083)
		(end 382.418336 -237.901226)
		(width 0.0889)
		(layer "B.Cu")
		(net "CLK_100M_DB2000_CPU0_BCLK1_DP")
	)
	(arc
		(start 375.274078 -237.901226)
		(mid 375.08688 -237.851083)
		(end 374.899682 -237.901226)
		(width 0.0889)
		(layer "B.Cu")
		(net "CLK_100M_DB2000_CPU0_BCLK1_DP")
	)
	(segment
		(start 237.868714 -129.397252)
		(end 238.124492 -129.397252)
		(width 0.13208)
		(layer "F.Cu")
		(net "CLK_100M_DB2000_CPU0_BCLK1_DN")
	)
	(segment
		(start 242.12042 -130.419348)
		(end 242.42268 -130.721608)
		(width 0.13208)
		(layer "F.Cu")
		(net "CLK_100M_DB2000_CPU0_BCLK1_DN")
	)
	(segment
		(start 239.30991 -129.633218)
		(end 241.207798 -130.419348)
		(width 0.13208)
		(layer "F.Cu")
		(net "CLK_100M_DB2000_CPU0_BCLK1_DN")
	)
	(segment
		(start 238.124492 -129.397252)
		(end 239.30991 -129.633218)
		(width 0.13208)
		(layer "F.Cu")
		(net "CLK_100M_DB2000_CPU0_BCLK1_DN")
	)
	(segment
		(start 369.91798 -236.319822)
		(end 369.918234 -236.319568)
		(width 0.13208)
		(layer "F.Cu")
		(net "CLK_100M_DB2000_CPU0_BCLK1_DN")
	)
	(segment
		(start 237.748064 -129.517902)
		(end 237.868714 -129.397252)
		(width 0.13208)
		(layer "F.Cu")
		(net "CLK_100M_DB2000_CPU0_BCLK1_DN")
	)
	(segment
		(start 369.918234 -236.319568)
		(end 369.918234 -235.783882)
		(width 0.13208)
		(layer "F.Cu")
		(net "CLK_100M_DB2000_CPU0_BCLK1_DN")
	)
	(segment
		(start 241.207798 -130.419348)
		(end 242.12042 -130.419348)
		(width 0.13208)
		(layer "F.Cu")
		(net "CLK_100M_DB2000_CPU0_BCLK1_DN")
	)
	(via
		(at 242.42268 -130.721608)
		(size 0.508)
		(drill 0.254)
		(layers "F.Cu" "B.Cu")
		(net "CLK_100M_DB2000_CPU0_BCLK1_DN")
	)
	(via
		(at 369.918234 -235.783882)
		(size 0.4572)
		(drill 0.2032)
		(layers "F.Cu" "B.Cu")
		(net "CLK_100M_DB2000_CPU0_BCLK1_DN")
	)
	(segment
		(start 368.956336 -168.091612)
		(end 370.459508 -168.39057)
		(width 0.13208)
		(layer "B.Cu")
		(net "CLK_100M_DB2000_CPU0_BCLK1_DN")
	)
	(segment
		(start 344.262964 -154.357578)
		(end 357.037894 -162.83686)
		(width 0.13208)
		(layer "B.Cu")
		(net "CLK_100M_DB2000_CPU0_BCLK1_DN")
	)
	(segment
		(start 392.066272 -193.124836)
		(end 397.0274 -198.085964)
		(width 0.13208)
		(layer "B.Cu")
		(net "CLK_100M_DB2000_CPU0_BCLK1_DN")
	)
	(segment
		(start 370.459508 -168.39057)
		(end 371.61724 -168.39057)
		(width 0.13208)
		(layer "B.Cu")
		(net "CLK_100M_DB2000_CPU0_BCLK1_DN")
	)
	(segment
		(start 266.64666 -134.250684)
		(end 306.352956 -142.14856)
		(width 0.13208)
		(layer "B.Cu")
		(net "CLK_100M_DB2000_CPU0_BCLK1_DN")
	)
	(segment
		(start 369.76177 -236.0549)
		(end 369.918234 -235.783882)
		(width 0.0889)
		(layer "B.Cu")
		(net "CLK_100M_DB2000_CPU0_BCLK1_DN")
	)
	(segment
		(start 392.699748 -233.31551)
		(end 392.423142 -233.592116)
		(width 0.13208)
		(layer "B.Cu")
		(net "CLK_100M_DB2000_CPU0_BCLK1_DN")
	)
	(segment
		(start 397.0274 -228.843332)
		(end 396.800578 -229.390702)
		(width 0.13208)
		(layer "B.Cu")
		(net "CLK_100M_DB2000_CPU0_BCLK1_DN")
	)
	(segment
		(start 390.869932 -235.145326)
		(end 390.593072 -235.422186)
		(width 0.13208)
		(layer "B.Cu")
		(net "CLK_100M_DB2000_CPU0_BCLK1_DN")
	)
	(segment
		(start 245.188232 -131.054602)
		(end 246.912892 -131.768596)
		(width 0.13208)
		(layer "B.Cu")
		(net "CLK_100M_DB2000_CPU0_BCLK1_DN")
	)
	(segment
		(start 372.939564 -237.727236)
		(end 372.924832 -237.735872)
		(width 0.0889)
		(layer "B.Cu")
		(net "CLK_100M_DB2000_CPU0_BCLK1_DN")
	)
	(segment
		(start 392.87577 -233.31551)
		(end 392.699748 -233.31551)
		(width 0.13208)
		(layer "B.Cu")
		(net "CLK_100M_DB2000_CPU0_BCLK1_DN")
	)
	(segment
		(start 381.948436 -237.735872)
		(end 381.938022 -237.729776)
		(width 0.0889)
		(layer "B.Cu")
		(net "CLK_100M_DB2000_CPU0_BCLK1_DN")
	)
	(segment
		(start 396.298674 -229.892606)
		(end 396.122652 -229.892606)
		(width 0.13208)
		(layer "B.Cu")
		(net "CLK_100M_DB2000_CPU0_BCLK1_DN")
	)
	(segment
		(start 391.605262 -234.409996)
		(end 391.605262 -234.586018)
		(width 0.13208)
		(layer "B.Cu")
		(net "CLK_100M_DB2000_CPU0_BCLK1_DN")
	)
	(segment
		(start 381.008382 -237.735872)
		(end 380.997968 -237.729776)
		(width 0.0889)
		(layer "B.Cu")
		(net "CLK_100M_DB2000_CPU0_BCLK1_DN")
	)
	(segment
		(start 371.999764 -237.727236)
		(end 371.985032 -237.735872)
		(width 0.0889)
		(layer "B.Cu")
		(net "CLK_100M_DB2000_CPU0_BCLK1_DN")
	)
	(segment
		(start 392.423142 -233.768138)
		(end 392.05789 -234.13339)
		(width 0.13208)
		(layer "B.Cu")
		(net "CLK_100M_DB2000_CPU0_BCLK1_DN")
	)
	(segment
		(start 377.638564 -237.727236)
		(end 377.623832 -237.735872)
		(width 0.0889)
		(layer "B.Cu")
		(net "CLK_100M_DB2000_CPU0_BCLK1_DN")
	)
	(segment
		(start 389.024368 -236.409992)
		(end 388.861808 -236.342682)
		(width 0.13208)
		(layer "B.Cu")
		(net "CLK_100M_DB2000_CPU0_BCLK1_DN")
	)
	(segment
		(start 242.441476 -130.721608)
		(end 242.743736 -130.419348)
		(width 0.13208)
		(layer "B.Cu")
		(net "CLK_100M_DB2000_CPU0_BCLK1_DN")
	)
	(segment
		(start 378.839984 -175.5013)
		(end 388.95655 -185.617866)
		(width 0.13208)
		(layer "B.Cu")
		(net "CLK_100M_DB2000_CPU0_BCLK1_DN")
	)
	(segment
		(start 357.037894 -162.83686)
		(end 362.024676 -164.866828)
		(width 0.13208)
		(layer "B.Cu")
		(net "CLK_100M_DB2000_CPU0_BCLK1_DN")
	)
	(segment
		(start 396.122652 -229.892606)
		(end 395.845792 -230.169466)
		(width 0.13208)
		(layer "B.Cu")
		(net "CLK_100M_DB2000_CPU0_BCLK1_DN")
	)
	(segment
		(start 388.861808 -236.342682)
		(end 388.500112 -236.492288)
		(width 0.13208)
		(layer "B.Cu")
		(net "CLK_100M_DB2000_CPU0_BCLK1_DN")
	)
	(segment
		(start 375.758964 -237.727236)
		(end 375.744232 -237.735872)
		(width 0.0889)
		(layer "B.Cu")
		(net "CLK_100M_DB2000_CPU0_BCLK1_DN")
	)
	(segment
		(start 369.7859 -236.144054)
		(end 369.76177 -236.0549)
		(width 0.0889)
		(layer "B.Cu")
		(net "CLK_100M_DB2000_CPU0_BCLK1_DN")
	)
	(segment
		(start 371.61724 -168.39057)
		(end 372.669562 -168.709848)
		(width 0.13208)
		(layer "B.Cu")
		(net "CLK_100M_DB2000_CPU0_BCLK1_DN")
	)
	(segment
		(start 376.698764 -237.727236)
		(end 376.684032 -237.735872)
		(width 0.0889)
		(layer "B.Cu")
		(net "CLK_100M_DB2000_CPU0_BCLK1_DN")
	)
	(segment
		(start 242.743736 -130.419348)
		(end 243.65458 -130.419348)
		(width 0.13208)
		(layer "B.Cu")
		(net "CLK_100M_DB2000_CPU0_BCLK1_DN")
	)
	(segment
		(start 385.567936 -237.145576)
		(end 383.871724 -237.145576)
		(width 0.0889)
		(layer "B.Cu")
		(net "CLK_100M_DB2000_CPU0_BCLK1_DN")
	)
	(segment
		(start 388.95655 -185.617866)
		(end 392.066272 -193.124836)
		(width 0.13208)
		(layer "B.Cu")
		(net "CLK_100M_DB2000_CPU0_BCLK1_DN")
	)
	(segment
		(start 388.432802 -236.655102)
		(end 387.33476 -237.110016)
		(width 0.13208)
		(layer "B.Cu")
		(net "CLK_100M_DB2000_CPU0_BCLK1_DN")
	)
	(segment
		(start 379.518164 -237.727236)
		(end 379.503432 -237.735872)
		(width 0.0889)
		(layer "B.Cu")
		(net "CLK_100M_DB2000_CPU0_BCLK1_DN")
	)
	(segment
		(start 383.871724 -237.145576)
		(end 383.34061 -237.67669)
		(width 0.0889)
		(layer "B.Cu")
		(net "CLK_100M_DB2000_CPU0_BCLK1_DN")
	)
	(segment
		(start 393.991592 -232.023666)
		(end 393.991592 -232.199688)
		(width 0.13208)
		(layer "B.Cu")
		(net "CLK_100M_DB2000_CPU0_BCLK1_DN")
	)
	(segment
		(start 370.483638 -237.426246)
		(end 370.483384 -237.425992)
		(width 0.0889)
		(layer "B.Cu")
		(net "CLK_100M_DB2000_CPU0_BCLK1_DN")
	)
	(segment
		(start 391.605262 -234.586018)
		(end 391.045954 -235.145326)
		(width 0.13208)
		(layer "B.Cu")
		(net "CLK_100M_DB2000_CPU0_BCLK1_DN")
	)
	(segment
		(start 388.500112 -236.492288)
		(end 388.432802 -236.655102)
		(width 0.13208)
		(layer "B.Cu")
		(net "CLK_100M_DB2000_CPU0_BCLK1_DN")
	)
	(segment
		(start 391.045954 -235.145326)
		(end 390.869932 -235.145326)
		(width 0.13208)
		(layer "B.Cu")
		(net "CLK_100M_DB2000_CPU0_BCLK1_DN")
	)
	(segment
		(start 367.075466 -167.312848)
		(end 368.956336 -168.091612)
		(width 0.13208)
		(layer "B.Cu")
		(net "CLK_100M_DB2000_CPU0_BCLK1_DN")
	)
	(segment
		(start 397.0274 -198.085964)
		(end 397.0274 -228.843332)
		(width 0.13208)
		(layer "B.Cu")
		(net "CLK_100M_DB2000_CPU0_BCLK1_DN")
	)
	(segment
		(start 396.800578 -229.390702)
		(end 396.298674 -229.892606)
		(width 0.13208)
		(layer "B.Cu")
		(net "CLK_100M_DB2000_CPU0_BCLK1_DN")
	)
	(segment
		(start 390.593072 -235.598208)
		(end 390.31672 -235.87456)
		(width 0.13208)
		(layer "B.Cu")
		(net "CLK_100M_DB2000_CPU0_BCLK1_DN")
	)
	(segment
		(start 390.31672 -235.87456)
		(end 389.024368 -236.409992)
		(width 0.13208)
		(layer "B.Cu")
		(net "CLK_100M_DB2000_CPU0_BCLK1_DN")
	)
	(segment
		(start 306.352956 -142.14856)
		(end 318.68872 -142.14856)
		(width 0.13208)
		(layer "B.Cu")
		(net "CLK_100M_DB2000_CPU0_BCLK1_DN")
	)
	(segment
		(start 385.86537 -237.111032)
		(end 385.624578 -237.111032)
		(width 0.13208)
		(layer "B.Cu")
		(net "CLK_100M_DB2000_CPU0_BCLK1_DN")
	)
	(segment
		(start 341.504778 -151.599646)
		(end 341.505032 -151.599646)
		(width 0.13208)
		(layer "B.Cu")
		(net "CLK_100M_DB2000_CPU0_BCLK1_DN")
	)
	(segment
		(start 387.33476 -237.110016)
		(end 385.866386 -237.110016)
		(width 0.13208)
		(layer "B.Cu")
		(net "CLK_100M_DB2000_CPU0_BCLK1_DN")
	)
	(segment
		(start 385.624578 -237.111032)
		(end 385.60248 -237.111032)
		(width 0.0889)
		(layer "B.Cu")
		(net "CLK_100M_DB2000_CPU0_BCLK1_DN")
	)
	(segment
		(start 372.669562 -168.709848)
		(end 375.619772 -170.681142)
		(width 0.13208)
		(layer "B.Cu")
		(net "CLK_100M_DB2000_CPU0_BCLK1_DN")
	)
	(segment
		(start 393.605004 -232.586276)
		(end 393.428982 -232.586276)
		(width 0.13208)
		(layer "B.Cu")
		(net "CLK_100M_DB2000_CPU0_BCLK1_DN")
	)
	(segment
		(start 370.200682 -236.922056)
		(end 370.192808 -236.917484)
		(width 0.0889)
		(layer "B.Cu")
		(net "CLK_100M_DB2000_CPU0_BCLK1_DN")
	)
	(segment
		(start 362.024676 -164.866828)
		(end 367.075466 -167.312848)
		(width 0.13208)
		(layer "B.Cu")
		(net "CLK_100M_DB2000_CPU0_BCLK1_DN")
	)
	(segment
		(start 244.596412 -130.809492)
		(end 244.663976 -130.972306)
		(width 0.13208)
		(layer "B.Cu")
		(net "CLK_100M_DB2000_CPU0_BCLK1_DN")
	)
	(segment
		(start 394.44422 -231.74706)
		(end 394.268198 -231.74706)
		(width 0.13208)
		(layer "B.Cu")
		(net "CLK_100M_DB2000_CPU0_BCLK1_DN")
	)
	(segment
		(start 394.268198 -231.74706)
		(end 393.991592 -232.023666)
		(width 0.13208)
		(layer "B.Cu")
		(net "CLK_100M_DB2000_CPU0_BCLK1_DN")
	)
	(segment
		(start 370.013484 -236.597952)
		(end 370.013484 -236.575854)
		(width 0.0889)
		(layer "B.Cu")
		(net "CLK_100M_DB2000_CPU0_BCLK1_DN")
	)
	(segment
		(start 370.206778 -236.925612)
		(end 370.201698 -236.922564)
		(width 0.0889)
		(layer "B.Cu")
		(net "CLK_100M_DB2000_CPU0_BCLK1_DN")
	)
	(segment
		(start 318.68872 -142.14856)
		(end 341.504778 -151.599646)
		(width 0.13208)
		(layer "B.Cu")
		(net "CLK_100M_DB2000_CPU0_BCLK1_DN")
	)
	(segment
		(start 246.912892 -131.768596)
		(end 252.27026 -132.834634)
		(width 0.13208)
		(layer "B.Cu")
		(net "CLK_100M_DB2000_CPU0_BCLK1_DN")
	)
	(segment
		(start 245.025418 -131.121912)
		(end 245.188232 -131.054602)
		(width 0.13208)
		(layer "B.Cu")
		(net "CLK_100M_DB2000_CPU0_BCLK1_DN")
	)
	(segment
		(start 395.845792 -230.345488)
		(end 395.56944 -230.62184)
		(width 0.13208)
		(layer "B.Cu")
		(net "CLK_100M_DB2000_CPU0_BCLK1_DN")
	)
	(segment
		(start 391.881868 -234.13339)
		(end 391.605262 -234.409996)
		(width 0.13208)
		(layer "B.Cu")
		(net "CLK_100M_DB2000_CPU0_BCLK1_DN")
	)
	(segment
		(start 252.27026 -132.834634)
		(end 266.64666 -134.250684)
		(width 0.13208)
		(layer "B.Cu")
		(net "CLK_100M_DB2000_CPU0_BCLK1_DN")
	)
	(segment
		(start 375.619772 -170.681142)
		(end 378.839984 -175.5013)
		(width 0.13208)
		(layer "B.Cu")
		(net "CLK_100M_DB2000_CPU0_BCLK1_DN")
	)
	(segment
		(start 393.152122 -232.863136)
		(end 393.152122 -233.039158)
		(width 0.13208)
		(layer "B.Cu")
		(net "CLK_100M_DB2000_CPU0_BCLK1_DN")
	)
	(segment
		(start 393.991592 -232.199688)
		(end 393.605004 -232.586276)
		(width 0.13208)
		(layer "B.Cu")
		(net "CLK_100M_DB2000_CPU0_BCLK1_DN")
	)
	(segment
		(start 374.819164 -237.727236)
		(end 374.804432 -237.735872)
		(width 0.0889)
		(layer "B.Cu")
		(net "CLK_100M_DB2000_CPU0_BCLK1_DN")
	)
	(segment
		(start 392.05789 -234.13339)
		(end 391.881868 -234.13339)
		(width 0.13208)
		(layer "B.Cu")
		(net "CLK_100M_DB2000_CPU0_BCLK1_DN")
	)
	(segment
		(start 371.059964 -237.727236)
		(end 371.045232 -237.735872)
		(width 0.0889)
		(layer "B.Cu")
		(net "CLK_100M_DB2000_CPU0_BCLK1_DN")
	)
	(segment
		(start 341.505032 -151.599646)
		(end 344.262964 -154.357578)
		(width 0.13208)
		(layer "B.Cu")
		(net "CLK_100M_DB2000_CPU0_BCLK1_DN")
	)
	(segment
		(start 395.56944 -230.62184)
		(end 395.393418 -230.62184)
		(width 0.13208)
		(layer "B.Cu")
		(net "CLK_100M_DB2000_CPU0_BCLK1_DN")
	)
	(segment
		(start 370.201698 -236.922564)
		(end 370.200682 -236.922056)
		(width 0.0889)
		(layer "B.Cu")
		(net "CLK_100M_DB2000_CPU0_BCLK1_DN")
	)
	(segment
		(start 395.845792 -230.169466)
		(end 395.845792 -230.345488)
		(width 0.13208)
		(layer "B.Cu")
		(net "CLK_100M_DB2000_CPU0_BCLK1_DN")
	)
	(segment
		(start 242.42268 -130.721608)
		(end 242.441476 -130.721608)
		(width 0.13208)
		(layer "B.Cu")
		(net "CLK_100M_DB2000_CPU0_BCLK1_DN")
	)
	(segment
		(start 392.423142 -233.592116)
		(end 392.423142 -233.768138)
		(width 0.13208)
		(layer "B.Cu")
		(net "CLK_100M_DB2000_CPU0_BCLK1_DN")
	)
	(segment
		(start 393.152122 -233.039158)
		(end 392.87577 -233.31551)
		(width 0.13208)
		(layer "B.Cu")
		(net "CLK_100M_DB2000_CPU0_BCLK1_DN")
	)
	(segment
		(start 378.578364 -237.727236)
		(end 378.563632 -237.735872)
		(width 0.0889)
		(layer "B.Cu")
		(net "CLK_100M_DB2000_CPU0_BCLK1_DN")
	)
	(segment
		(start 395.116812 -231.074468)
		(end 394.44422 -231.74706)
		(width 0.13208)
		(layer "B.Cu")
		(net "CLK_100M_DB2000_CPU0_BCLK1_DN")
	)
	(segment
		(start 395.393418 -230.62184)
		(end 395.116812 -230.898446)
		(width 0.13208)
		(layer "B.Cu")
		(net "CLK_100M_DB2000_CPU0_BCLK1_DN")
	)
	(segment
		(start 385.60248 -237.111032)
		(end 385.567936 -237.145576)
		(width 0.0889)
		(layer "B.Cu")
		(net "CLK_100M_DB2000_CPU0_BCLK1_DN")
	)
	(segment
		(start 393.428982 -232.586276)
		(end 393.152122 -232.863136)
		(width 0.13208)
		(layer "B.Cu")
		(net "CLK_100M_DB2000_CPU0_BCLK1_DN")
	)
	(segment
		(start 385.866386 -237.110016)
		(end 385.86537 -237.111032)
		(width 0.13208)
		(layer "B.Cu")
		(net "CLK_100M_DB2000_CPU0_BCLK1_DN")
	)
	(segment
		(start 370.483384 -237.425992)
		(end 370.483384 -237.411514)
		(width 0.0889)
		(layer "B.Cu")
		(net "CLK_100M_DB2000_CPU0_BCLK1_DN")
	)
	(segment
		(start 244.663976 -130.972306)
		(end 245.025418 -131.121912)
		(width 0.13208)
		(layer "B.Cu")
		(net "CLK_100M_DB2000_CPU0_BCLK1_DN")
	)
	(segment
		(start 390.593072 -235.422186)
		(end 390.593072 -235.598208)
		(width 0.13208)
		(layer "B.Cu")
		(net "CLK_100M_DB2000_CPU0_BCLK1_DN")
	)
	(segment
		(start 243.65458 -130.419348)
		(end 244.596412 -130.809492)
		(width 0.13208)
		(layer "B.Cu")
		(net "CLK_100M_DB2000_CPU0_BCLK1_DN")
	)
	(segment
		(start 395.116812 -230.898446)
		(end 395.116812 -231.074468)
		(width 0.13208)
		(layer "B.Cu")
		(net "CLK_100M_DB2000_CPU0_BCLK1_DN")
	)
	(arc
		(start 382.888236 -237.735872)
		(mid 382.605534 -237.66013)
		(end 382.322832 -237.735872)
		(width 0.0889)
		(layer "B.Cu")
		(net "CLK_100M_DB2000_CPU0_BCLK1_DN")
	)
	(arc
		(start 370.483384 -237.411514)
		(mid 370.409393 -237.131948)
		(end 370.206778 -236.925612)
		(width 0.0889)
		(layer "B.Cu")
		(net "CLK_100M_DB2000_CPU0_BCLK1_DN")
	)
	(arc
		(start 381.382778 -237.735872)
		(mid 381.19558 -237.786015)
		(end 381.008382 -237.735872)
		(width 0.0889)
		(layer "B.Cu")
		(net "CLK_100M_DB2000_CPU0_BCLK1_DN")
	)
	(arc
		(start 372.924832 -237.735872)
		(mid 372.737634 -237.786015)
		(end 372.550436 -237.735872)
		(width 0.0889)
		(layer "B.Cu")
		(net "CLK_100M_DB2000_CPU0_BCLK1_DN")
	)
	(arc
		(start 373.490236 -237.735872)
		(mid 373.216007 -237.659947)
		(end 372.939564 -237.727236)
		(width 0.0889)
		(layer "B.Cu")
		(net "CLK_100M_DB2000_CPU0_BCLK1_DN")
	)
	(arc
		(start 370.192808 -236.917484)
		(mid 370.061396 -236.781152)
		(end 370.013484 -236.597952)
		(width 0.0889)
		(layer "B.Cu")
		(net "CLK_100M_DB2000_CPU0_BCLK1_DN")
	)
	(arc
		(start 379.503432 -237.735872)
		(mid 379.316234 -237.786015)
		(end 379.129036 -237.735872)
		(width 0.0889)
		(layer "B.Cu")
		(net "CLK_100M_DB2000_CPU0_BCLK1_DN")
	)
	(arc
		(start 383.34061 -237.67669)
		(mid 383.303567 -237.708846)
		(end 383.262632 -237.735872)
		(width 0.0889)
		(layer "B.Cu")
		(net "CLK_100M_DB2000_CPU0_BCLK1_DN")
	)
	(arc
		(start 383.262632 -237.735872)
		(mid 383.075434 -237.786015)
		(end 382.888236 -237.735872)
		(width 0.0889)
		(layer "B.Cu")
		(net "CLK_100M_DB2000_CPU0_BCLK1_DN")
	)
	(arc
		(start 379.129036 -237.735872)
		(mid 378.854807 -237.659947)
		(end 378.578364 -237.727236)
		(width 0.0889)
		(layer "B.Cu")
		(net "CLK_100M_DB2000_CPU0_BCLK1_DN")
	)
	(arc
		(start 371.985032 -237.735872)
		(mid 371.797834 -237.786015)
		(end 371.610636 -237.735872)
		(width 0.0889)
		(layer "B.Cu")
		(net "CLK_100M_DB2000_CPU0_BCLK1_DN")
	)
	(arc
		(start 375.369836 -237.735872)
		(mid 375.095607 -237.659947)
		(end 374.819164 -237.727236)
		(width 0.0889)
		(layer "B.Cu")
		(net "CLK_100M_DB2000_CPU0_BCLK1_DN")
	)
	(arc
		(start 378.189236 -237.735872)
		(mid 377.915007 -237.659947)
		(end 377.638564 -237.727236)
		(width 0.0889)
		(layer "B.Cu")
		(net "CLK_100M_DB2000_CPU0_BCLK1_DN")
	)
	(arc
		(start 375.744232 -237.735872)
		(mid 375.557034 -237.786015)
		(end 375.369836 -237.735872)
		(width 0.0889)
		(layer "B.Cu")
		(net "CLK_100M_DB2000_CPU0_BCLK1_DN")
	)
	(arc
		(start 376.309636 -237.735872)
		(mid 376.035407 -237.659947)
		(end 375.758964 -237.727236)
		(width 0.0889)
		(layer "B.Cu")
		(net "CLK_100M_DB2000_CPU0_BCLK1_DN")
	)
	(arc
		(start 371.610636 -237.735872)
		(mid 371.336407 -237.659947)
		(end 371.059964 -237.727236)
		(width 0.0889)
		(layer "B.Cu")
		(net "CLK_100M_DB2000_CPU0_BCLK1_DN")
	)
	(arc
		(start 377.623832 -237.735872)
		(mid 377.436634 -237.786015)
		(end 377.249436 -237.735872)
		(width 0.0889)
		(layer "B.Cu")
		(net "CLK_100M_DB2000_CPU0_BCLK1_DN")
	)
	(arc
		(start 376.684032 -237.735872)
		(mid 376.496834 -237.786015)
		(end 376.309636 -237.735872)
		(width 0.0889)
		(layer "B.Cu")
		(net "CLK_100M_DB2000_CPU0_BCLK1_DN")
	)
	(arc
		(start 369.802918 -236.157008)
		(mid 369.79447 -236.150451)
		(end 369.7859 -236.144054)
		(width 0.0889)
		(layer "B.Cu")
		(net "CLK_100M_DB2000_CPU0_BCLK1_DN")
	)
	(arc
		(start 374.804432 -237.735872)
		(mid 374.617234 -237.786015)
		(end 374.430036 -237.735872)
		(width 0.0889)
		(layer "B.Cu")
		(net "CLK_100M_DB2000_CPU0_BCLK1_DN")
	)
	(arc
		(start 370.013484 -236.575854)
		(mid 369.95368 -236.343563)
		(end 369.802918 -236.157008)
		(width 0.0889)
		(layer "B.Cu")
		(net "CLK_100M_DB2000_CPU0_BCLK1_DN")
	)
	(arc
		(start 380.068836 -237.735872)
		(mid 379.794607 -237.659947)
		(end 379.518164 -237.727236)
		(width 0.0889)
		(layer "B.Cu")
		(net "CLK_100M_DB2000_CPU0_BCLK1_DN")
	)
	(arc
		(start 380.443232 -237.735872)
		(mid 380.256034 -237.786015)
		(end 380.068836 -237.735872)
		(width 0.0889)
		(layer "B.Cu")
		(net "CLK_100M_DB2000_CPU0_BCLK1_DN")
	)
	(arc
		(start 382.322832 -237.735872)
		(mid 382.135634 -237.786015)
		(end 381.948436 -237.735872)
		(width 0.0889)
		(layer "B.Cu")
		(net "CLK_100M_DB2000_CPU0_BCLK1_DN")
	)
	(arc
		(start 378.563632 -237.735872)
		(mid 378.376434 -237.786015)
		(end 378.189236 -237.735872)
		(width 0.0889)
		(layer "B.Cu")
		(net "CLK_100M_DB2000_CPU0_BCLK1_DN")
	)
	(arc
		(start 377.249436 -237.735872)
		(mid 376.975207 -237.659947)
		(end 376.698764 -237.727236)
		(width 0.0889)
		(layer "B.Cu")
		(net "CLK_100M_DB2000_CPU0_BCLK1_DN")
	)
	(arc
		(start 372.550436 -237.735872)
		(mid 372.276207 -237.659947)
		(end 371.999764 -237.727236)
		(width 0.0889)
		(layer "B.Cu")
		(net "CLK_100M_DB2000_CPU0_BCLK1_DN")
	)
	(arc
		(start 374.430036 -237.735872)
		(mid 374.147334 -237.66013)
		(end 373.864632 -237.735872)
		(width 0.0889)
		(layer "B.Cu")
		(net "CLK_100M_DB2000_CPU0_BCLK1_DN")
	)
	(arc
		(start 373.864632 -237.735872)
		(mid 373.677434 -237.786015)
		(end 373.490236 -237.735872)
		(width 0.0889)
		(layer "B.Cu")
		(net "CLK_100M_DB2000_CPU0_BCLK1_DN")
	)
	(arc
		(start 381.938022 -237.729776)
		(mid 381.65959 -237.659962)
		(end 381.382778 -237.735872)
		(width 0.0889)
		(layer "B.Cu")
		(net "CLK_100M_DB2000_CPU0_BCLK1_DN")
	)
	(arc
		(start 380.997968 -237.729776)
		(mid 380.71979 -237.660084)
		(end 380.443232 -237.735872)
		(width 0.0889)
		(layer "B.Cu")
		(net "CLK_100M_DB2000_CPU0_BCLK1_DN")
	)
	(arc
		(start 371.045232 -237.735872)
		(mid 370.677119 -237.739415)
		(end 370.483638 -237.426246)
		(width 0.0889)
		(layer "B.Cu")
		(net "CLK_100M_DB2000_CPU0_BCLK1_DN")
	)
	(segment
		(start 237.86846 -128.138174)
		(end 238.81334 -128.138174)
		(width 0.13208)
		(layer "F.Cu")
		(net "CLK_100M_DB2000_CPU0_BCLK0_DP")
	)
	(segment
		(start 350.182434 -237.947454)
		(end 350.182434 -237.411514)
		(width 0.13208)
		(layer "F.Cu")
		(net "CLK_100M_DB2000_CPU0_BCLK0_DP")
	)
	(segment
		(start 237.748064 -128.017778)
		(end 237.86846 -128.138174)
		(width 0.13208)
		(layer "F.Cu")
		(net "CLK_100M_DB2000_CPU0_BCLK0_DP")
	)
	(segment
		(start 350.18218 -237.947454)
		(end 350.182434 -237.947454)
		(width 0.13208)
		(layer "F.Cu")
		(net "CLK_100M_DB2000_CPU0_BCLK0_DP")
	)
	(segment
		(start 240.166398 -128.458468)
		(end 240.468658 -128.156208)
		(width 0.13208)
		(layer "F.Cu")
		(net "CLK_100M_DB2000_CPU0_BCLK0_DP")
	)
	(segment
		(start 238.81334 -128.138174)
		(end 239.58677 -128.458468)
		(width 0.13208)
		(layer "F.Cu")
		(net "CLK_100M_DB2000_CPU0_BCLK0_DP")
	)
	(segment
		(start 239.58677 -128.458468)
		(end 240.166398 -128.458468)
		(width 0.13208)
		(layer "F.Cu")
		(net "CLK_100M_DB2000_CPU0_BCLK0_DP")
	)
	(via
		(at 240.468658 -128.156208)
		(size 0.508)
		(drill 0.254)
		(layers "F.Cu" "B.Cu")
		(net "CLK_100M_DB2000_CPU0_BCLK0_DP")
	)
	(via
		(at 350.182434 -237.411514)
		(size 0.4572)
		(drill 0.2032)
		(layers "F.Cu" "B.Cu")
		(net "CLK_100M_DB2000_CPU0_BCLK0_DP")
	)
	(segment
		(start 331.75448 -239.402112)
		(end 331.78877 -239.436402)
		(width 0.0889)
		(layer "B.Cu")
		(net "CLK_100M_DB2000_CPU0_BCLK0_DP")
	)
	(segment
		(start 301.07636 -197.963028)
		(end 301.63008 -199.29983)
		(width 0.13208)
		(layer "B.Cu")
		(net "CLK_100M_DB2000_CPU0_BCLK0_DP")
	)
	(segment
		(start 320.509138 -241.798094)
		(end 327.524364 -241.798094)
		(width 0.13208)
		(layer "B.Cu")
		(net "CLK_100M_DB2000_CPU0_BCLK0_DP")
	)
	(segment
		(start 340.971632 -237.735872)
		(end 340.986364 -237.727236)
		(width 0.0889)
		(layer "B.Cu")
		(net "CLK_100M_DB2000_CPU0_BCLK0_DP")
	)
	(segment
		(start 240.468658 -128.156208)
		(end 240.770918 -128.458468)
		(width 0.13208)
		(layer "B.Cu")
		(net "CLK_100M_DB2000_CPU0_BCLK0_DP")
	)
	(segment
		(start 252.595888 -159.505142)
		(end 272.828512 -179.737766)
		(width 0.13208)
		(layer "B.Cu")
		(net "CLK_100M_DB2000_CPU0_BCLK0_DP")
	)
	(segment
		(start 337.212432 -237.735872)
		(end 337.227164 -237.727236)
		(width 0.0889)
		(layer "B.Cu")
		(net "CLK_100M_DB2000_CPU0_BCLK0_DP")
	)
	(segment
		(start 241.469418 -134.49427)
		(end 246.405908 -146.41195)
		(width 0.13208)
		(layer "B.Cu")
		(net "CLK_100M_DB2000_CPU0_BCLK0_DP")
	)
	(segment
		(start 348.943422 -236.932216)
		(end 348.974664 -236.914436)
		(width 0.0889)
		(layer "B.Cu")
		(net "CLK_100M_DB2000_CPU0_BCLK0_DP")
	)
	(segment
		(start 301.07636 -193.502788)
		(end 301.07636 -197.963028)
		(width 0.13208)
		(layer "B.Cu")
		(net "CLK_100M_DB2000_CPU0_BCLK0_DP")
	)
	(segment
		(start 298.0563 -186.344814)
		(end 299.859954 -190.699898)
		(width 0.13208)
		(layer "B.Cu")
		(net "CLK_100M_DB2000_CPU0_BCLK0_DP")
	)
	(segment
		(start 309.685436 -245.383304)
		(end 309.92191 -245.481348)
		(width 0.13208)
		(layer "B.Cu")
		(net "CLK_100M_DB2000_CPU0_BCLK0_DP")
	)
	(segment
		(start 333.604108 -239.43691)
		(end 335.215484 -237.825534)
		(width 0.0889)
		(layer "B.Cu")
		(net "CLK_100M_DB2000_CPU0_BCLK0_DP")
	)
	(segment
		(start 309.92191 -245.481348)
		(end 310.57215 -245.481348)
		(width 0.13208)
		(layer "B.Cu")
		(net "CLK_100M_DB2000_CPU0_BCLK0_DP")
	)
	(segment
		(start 241.469418 -131.446778)
		(end 241.469418 -134.49427)
		(width 0.13208)
		(layer "B.Cu")
		(net "CLK_100M_DB2000_CPU0_BCLK0_DP")
	)
	(segment
		(start 346.610178 -237.735872)
		(end 346.620592 -237.729776)
		(width 0.0889)
		(layer "B.Cu")
		(net "CLK_100M_DB2000_CPU0_BCLK0_DP")
	)
	(segment
		(start 348.677484 -237.411514)
		(end 348.677738 -237.411514)
		(width 0.0889)
		(layer "B.Cu")
		(net "CLK_100M_DB2000_CPU0_BCLK0_DP")
	)
	(segment
		(start 333.6036 -239.436402)
		(end 333.604108 -239.43691)
		(width 0.0889)
		(layer "B.Cu")
		(net "CLK_100M_DB2000_CPU0_BCLK0_DP")
	)
	(segment
		(start 349.86976 -237.411514)
		(end 350.182434 -237.411514)
		(width 0.0889)
		(layer "B.Cu")
		(net "CLK_100M_DB2000_CPU0_BCLK0_DP")
	)
	(segment
		(start 302.03648 -239.512348)
		(end 305.07178 -240.769648)
		(width 0.13208)
		(layer "B.Cu")
		(net "CLK_100M_DB2000_CPU0_BCLK0_DP")
	)
	(segment
		(start 241.412522 -128.458468)
		(end 241.81816 -128.864106)
		(width 0.13208)
		(layer "B.Cu")
		(net "CLK_100M_DB2000_CPU0_BCLK0_DP")
	)
	(segment
		(start 241.81816 -129.69367)
		(end 241.469418 -131.446778)
		(width 0.13208)
		(layer "B.Cu")
		(net "CLK_100M_DB2000_CPU0_BCLK0_DP")
	)
	(segment
		(start 301.63008 -199.29983)
		(end 301.63008 -239.105948)
		(width 0.13208)
		(layer "B.Cu")
		(net "CLK_100M_DB2000_CPU0_BCLK0_DP")
	)
	(segment
		(start 310.57215 -245.481348)
		(end 312.04408 -244.871748)
		(width 0.13208)
		(layer "B.Cu")
		(net "CLK_100M_DB2000_CPU0_BCLK0_DP")
	)
	(segment
		(start 314.41263 -243.01069)
		(end 320.509138 -241.798094)
		(width 0.13208)
		(layer "B.Cu")
		(net "CLK_100M_DB2000_CPU0_BCLK0_DP")
	)
	(segment
		(start 341.911432 -237.735872)
		(end 341.926164 -237.727236)
		(width 0.0889)
		(layer "B.Cu")
		(net "CLK_100M_DB2000_CPU0_BCLK0_DP")
	)
	(segment
		(start 241.81816 -128.864106)
		(end 241.81816 -129.69367)
		(width 0.13208)
		(layer "B.Cu")
		(net "CLK_100M_DB2000_CPU0_BCLK0_DP")
	)
	(segment
		(start 327.524364 -241.798094)
		(end 330.115164 -240.724944)
		(width 0.13208)
		(layer "B.Cu")
		(net "CLK_100M_DB2000_CPU0_BCLK0_DP")
	)
	(segment
		(start 331.732382 -239.402112)
		(end 331.75448 -239.402112)
		(width 0.0889)
		(layer "B.Cu")
		(net "CLK_100M_DB2000_CPU0_BCLK0_DP")
	)
	(segment
		(start 336.272632 -237.735872)
		(end 336.287364 -237.727236)
		(width 0.0889)
		(layer "B.Cu")
		(net "CLK_100M_DB2000_CPU0_BCLK0_DP")
	)
	(segment
		(start 272.828512 -179.737766)
		(end 275.54809 -180.864256)
		(width 0.13208)
		(layer "B.Cu")
		(net "CLK_100M_DB2000_CPU0_BCLK0_DP")
	)
	(segment
		(start 343.791032 -237.735872)
		(end 343.805764 -237.727236)
		(width 0.0889)
		(layer "B.Cu")
		(net "CLK_100M_DB2000_CPU0_BCLK0_DP")
	)
	(segment
		(start 295.232328 -183.520842)
		(end 298.0563 -186.344814)
		(width 0.13208)
		(layer "B.Cu")
		(net "CLK_100M_DB2000_CPU0_BCLK0_DP")
	)
	(segment
		(start 301.63008 -239.105948)
		(end 302.03648 -239.512348)
		(width 0.13208)
		(layer "B.Cu")
		(net "CLK_100M_DB2000_CPU0_BCLK0_DP")
	)
	(segment
		(start 338.152232 -237.735872)
		(end 338.166964 -237.727236)
		(width 0.0889)
		(layer "B.Cu")
		(net "CLK_100M_DB2000_CPU0_BCLK0_DP")
	)
	(segment
		(start 331.78877 -239.436402)
		(end 333.6036 -239.436402)
		(width 0.0889)
		(layer "B.Cu")
		(net "CLK_100M_DB2000_CPU0_BCLK0_DP")
	)
	(segment
		(start 340.031578 -237.735872)
		(end 340.041992 -237.729776)
		(width 0.0889)
		(layer "B.Cu")
		(net "CLK_100M_DB2000_CPU0_BCLK0_DP")
	)
	(segment
		(start 342.851232 -237.735872)
		(end 342.865964 -237.727236)
		(width 0.0889)
		(layer "B.Cu")
		(net "CLK_100M_DB2000_CPU0_BCLK0_DP")
	)
	(segment
		(start 305.07178 -240.769648)
		(end 309.685436 -245.383304)
		(width 0.13208)
		(layer "B.Cu")
		(net "CLK_100M_DB2000_CPU0_BCLK0_DP")
	)
	(segment
		(start 275.54809 -180.864256)
		(end 288.818828 -180.864256)
		(width 0.13208)
		(layer "B.Cu")
		(net "CLK_100M_DB2000_CPU0_BCLK0_DP")
	)
	(segment
		(start 288.818828 -180.864256)
		(end 295.232328 -183.520842)
		(width 0.13208)
		(layer "B.Cu")
		(net "CLK_100M_DB2000_CPU0_BCLK0_DP")
	)
	(segment
		(start 299.859954 -190.699898)
		(end 300.006258 -190.918846)
		(width 0.13208)
		(layer "B.Cu")
		(net "CLK_100M_DB2000_CPU0_BCLK0_DP")
	)
	(segment
		(start 349.803974 -237.345728)
		(end 349.86976 -237.411514)
		(width 0.0889)
		(layer "B.Cu")
		(net "CLK_100M_DB2000_CPU0_BCLK0_DP")
	)
	(segment
		(start 312.04408 -244.871748)
		(end 313.546236 -243.369592)
		(width 0.13208)
		(layer "B.Cu")
		(net "CLK_100M_DB2000_CPU0_BCLK0_DP")
	)
	(segment
		(start 246.405908 -146.41195)
		(end 252.595888 -159.505142)
		(width 0.13208)
		(layer "B.Cu")
		(net "CLK_100M_DB2000_CPU0_BCLK0_DP")
	)
	(segment
		(start 300.006258 -190.918846)
		(end 301.07636 -193.502788)
		(width 0.13208)
		(layer "B.Cu")
		(net "CLK_100M_DB2000_CPU0_BCLK0_DP")
	)
	(segment
		(start 330.115164 -240.724944)
		(end 331.437996 -239.402112)
		(width 0.13208)
		(layer "B.Cu")
		(net "CLK_100M_DB2000_CPU0_BCLK0_DP")
	)
	(segment
		(start 347.550232 -237.735872)
		(end 347.564964 -237.727236)
		(width 0.0889)
		(layer "B.Cu")
		(net "CLK_100M_DB2000_CPU0_BCLK0_DP")
	)
	(segment
		(start 331.437996 -239.402112)
		(end 331.732382 -239.402112)
		(width 0.13208)
		(layer "B.Cu")
		(net "CLK_100M_DB2000_CPU0_BCLK0_DP")
	)
	(segment
		(start 346.225368 -237.729776)
		(end 346.235782 -237.735872)
		(width 0.0889)
		(layer "B.Cu")
		(net "CLK_100M_DB2000_CPU0_BCLK0_DP")
	)
	(segment
		(start 313.546236 -243.369592)
		(end 314.41263 -243.01069)
		(width 0.13208)
		(layer "B.Cu")
		(net "CLK_100M_DB2000_CPU0_BCLK0_DP")
	)
	(segment
		(start 349.541846 -236.932216)
		(end 349.541846 -236.931962)
		(width 0.0889)
		(layer "B.Cu")
		(net "CLK_100M_DB2000_CPU0_BCLK0_DP")
	)
	(segment
		(start 344.730832 -237.735872)
		(end 344.745564 -237.727236)
		(width 0.0889)
		(layer "B.Cu")
		(net "CLK_100M_DB2000_CPU0_BCLK0_DP")
	)
	(segment
		(start 339.646768 -237.729776)
		(end 339.657182 -237.735872)
		(width 0.0889)
		(layer "B.Cu")
		(net "CLK_100M_DB2000_CPU0_BCLK0_DP")
	)
	(segment
		(start 349.510604 -236.914436)
		(end 349.541846 -236.932216)
		(width 0.0889)
		(layer "B.Cu")
		(net "CLK_100M_DB2000_CPU0_BCLK0_DP")
	)
	(segment
		(start 240.770918 -128.458468)
		(end 241.412522 -128.458468)
		(width 0.13208)
		(layer "B.Cu")
		(net "CLK_100M_DB2000_CPU0_BCLK0_DP")
	)
	(arc
		(start 344.356436 -237.735872)
		(mid 344.543634 -237.786015)
		(end 344.730832 -237.735872)
		(width 0.0889)
		(layer "B.Cu")
		(net "CLK_100M_DB2000_CPU0_BCLK0_DP")
	)
	(arc
		(start 348.115636 -237.735872)
		(mid 348.490111 -237.735826)
		(end 348.677484 -237.411514)
		(width 0.0889)
		(layer "B.Cu")
		(net "CLK_100M_DB2000_CPU0_BCLK0_DP")
	)
	(arc
		(start 349.80118 -237.3249)
		(mid 349.802675 -237.335301)
		(end 349.803974 -237.345728)
		(width 0.0889)
		(layer "B.Cu")
		(net "CLK_100M_DB2000_CPU0_BCLK0_DP")
	)
	(arc
		(start 344.745564 -237.727236)
		(mid 345.022005 -237.66007)
		(end 345.296236 -237.735872)
		(width 0.0889)
		(layer "B.Cu")
		(net "CLK_100M_DB2000_CPU0_BCLK0_DP")
	)
	(arc
		(start 341.926164 -237.727236)
		(mid 342.202605 -237.66007)
		(end 342.476836 -237.735872)
		(width 0.0889)
		(layer "B.Cu")
		(net "CLK_100M_DB2000_CPU0_BCLK0_DP")
	)
	(arc
		(start 347.564964 -237.727236)
		(mid 347.841405 -237.66007)
		(end 348.115636 -237.735872)
		(width 0.0889)
		(layer "B.Cu")
		(net "CLK_100M_DB2000_CPU0_BCLK0_DP")
	)
	(arc
		(start 341.537036 -237.735872)
		(mid 341.724234 -237.786015)
		(end 341.911432 -237.735872)
		(width 0.0889)
		(layer "B.Cu")
		(net "CLK_100M_DB2000_CPU0_BCLK0_DP")
	)
	(arc
		(start 335.215484 -237.825534)
		(mid 335.275151 -237.77374)
		(end 335.341468 -237.730792)
		(width 0.0889)
		(layer "B.Cu")
		(net "CLK_100M_DB2000_CPU0_BCLK0_DP")
	)
	(arc
		(start 348.974664 -236.914436)
		(mid 349.242634 -236.843331)
		(end 349.510604 -236.914436)
		(width 0.0889)
		(layer "B.Cu")
		(net "CLK_100M_DB2000_CPU0_BCLK0_DP")
	)
	(arc
		(start 339.092032 -237.735872)
		(mid 339.368591 -237.660163)
		(end 339.646768 -237.729776)
		(width 0.0889)
		(layer "B.Cu")
		(net "CLK_100M_DB2000_CPU0_BCLK0_DP")
	)
	(arc
		(start 345.670632 -237.735872)
		(mid 345.947191 -237.660163)
		(end 346.225368 -237.729776)
		(width 0.0889)
		(layer "B.Cu")
		(net "CLK_100M_DB2000_CPU0_BCLK0_DP")
	)
	(arc
		(start 335.898236 -237.735872)
		(mid 336.085434 -237.786015)
		(end 336.272632 -237.735872)
		(width 0.0889)
		(layer "B.Cu")
		(net "CLK_100M_DB2000_CPU0_BCLK0_DP")
	)
	(arc
		(start 340.597236 -237.735872)
		(mid 340.784434 -237.786015)
		(end 340.971632 -237.735872)
		(width 0.0889)
		(layer "B.Cu")
		(net "CLK_100M_DB2000_CPU0_BCLK0_DP")
	)
	(arc
		(start 342.476836 -237.735872)
		(mid 342.664034 -237.786015)
		(end 342.851232 -237.735872)
		(width 0.0889)
		(layer "B.Cu")
		(net "CLK_100M_DB2000_CPU0_BCLK0_DP")
	)
	(arc
		(start 337.227164 -237.727236)
		(mid 337.503605 -237.66007)
		(end 337.777836 -237.735872)
		(width 0.0889)
		(layer "B.Cu")
		(net "CLK_100M_DB2000_CPU0_BCLK0_DP")
	)
	(arc
		(start 336.287364 -237.727236)
		(mid 336.563805 -237.66007)
		(end 336.838036 -237.735872)
		(width 0.0889)
		(layer "B.Cu")
		(net "CLK_100M_DB2000_CPU0_BCLK0_DP")
	)
	(arc
		(start 337.777836 -237.735872)
		(mid 337.965034 -237.786015)
		(end 338.152232 -237.735872)
		(width 0.0889)
		(layer "B.Cu")
		(net "CLK_100M_DB2000_CPU0_BCLK0_DP")
	)
	(arc
		(start 346.235782 -237.735872)
		(mid 346.42298 -237.786015)
		(end 346.610178 -237.735872)
		(width 0.0889)
		(layer "B.Cu")
		(net "CLK_100M_DB2000_CPU0_BCLK0_DP")
	)
	(arc
		(start 338.166964 -237.727236)
		(mid 338.443405 -237.66007)
		(end 338.717636 -237.735872)
		(width 0.0889)
		(layer "B.Cu")
		(net "CLK_100M_DB2000_CPU0_BCLK0_DP")
	)
	(arc
		(start 342.865964 -237.727236)
		(mid 343.142405 -237.66007)
		(end 343.416636 -237.735872)
		(width 0.0889)
		(layer "B.Cu")
		(net "CLK_100M_DB2000_CPU0_BCLK0_DP")
	)
	(arc
		(start 336.838036 -237.735872)
		(mid 337.025234 -237.786015)
		(end 337.212432 -237.735872)
		(width 0.0889)
		(layer "B.Cu")
		(net "CLK_100M_DB2000_CPU0_BCLK0_DP")
	)
	(arc
		(start 346.620592 -237.729776)
		(mid 346.899024 -237.659962)
		(end 347.175836 -237.735872)
		(width 0.0889)
		(layer "B.Cu")
		(net "CLK_100M_DB2000_CPU0_BCLK0_DP")
	)
	(arc
		(start 340.041992 -237.729776)
		(mid 340.320424 -237.659962)
		(end 340.597236 -237.735872)
		(width 0.0889)
		(layer "B.Cu")
		(net "CLK_100M_DB2000_CPU0_BCLK0_DP")
	)
	(arc
		(start 335.341468 -237.730792)
		(mid 335.62051 -237.660107)
		(end 335.898236 -237.735872)
		(width 0.0889)
		(layer "B.Cu")
		(net "CLK_100M_DB2000_CPU0_BCLK0_DP")
	)
	(arc
		(start 343.416636 -237.735872)
		(mid 343.603834 -237.786015)
		(end 343.791032 -237.735872)
		(width 0.0889)
		(layer "B.Cu")
		(net "CLK_100M_DB2000_CPU0_BCLK0_DP")
	)
	(arc
		(start 340.986364 -237.727236)
		(mid 341.262805 -237.66007)
		(end 341.537036 -237.735872)
		(width 0.0889)
		(layer "B.Cu")
		(net "CLK_100M_DB2000_CPU0_BCLK0_DP")
	)
	(arc
		(start 339.657182 -237.735872)
		(mid 339.84438 -237.786015)
		(end 340.031578 -237.735872)
		(width 0.0889)
		(layer "B.Cu")
		(net "CLK_100M_DB2000_CPU0_BCLK0_DP")
	)
	(arc
		(start 347.175836 -237.735872)
		(mid 347.363034 -237.786015)
		(end 347.550232 -237.735872)
		(width 0.0889)
		(layer "B.Cu")
		(net "CLK_100M_DB2000_CPU0_BCLK0_DP")
	)
	(arc
		(start 348.677738 -237.411514)
		(mid 348.748603 -237.137512)
		(end 348.943422 -236.932216)
		(width 0.0889)
		(layer "B.Cu")
		(net "CLK_100M_DB2000_CPU0_BCLK0_DP")
	)
	(arc
		(start 345.296236 -237.735872)
		(mid 345.483434 -237.786015)
		(end 345.670632 -237.735872)
		(width 0.0889)
		(layer "B.Cu")
		(net "CLK_100M_DB2000_CPU0_BCLK0_DP")
	)
	(arc
		(start 343.805764 -237.727236)
		(mid 344.082205 -237.66007)
		(end 344.356436 -237.735872)
		(width 0.0889)
		(layer "B.Cu")
		(net "CLK_100M_DB2000_CPU0_BCLK0_DP")
	)
	(arc
		(start 349.541846 -236.931962)
		(mid 349.714381 -237.100141)
		(end 349.80118 -237.3249)
		(width 0.0889)
		(layer "B.Cu")
		(net "CLK_100M_DB2000_CPU0_BCLK0_DP")
	)
	(arc
		(start 338.717636 -237.735872)
		(mid 338.904834 -237.786015)
		(end 339.092032 -237.735872)
		(width 0.0889)
		(layer "B.Cu")
		(net "CLK_100M_DB2000_CPU0_BCLK0_DP")
	)
	(segment
		(start 238.761778 -128.397254)
		(end 239.535208 -128.717548)
		(width 0.13208)
		(layer "F.Cu")
		(net "CLK_100M_DB2000_CPU0_BCLK0_DN")
	)
	(segment
		(start 237.748064 -128.517904)
		(end 237.868714 -128.397254)
		(width 0.13208)
		(layer "F.Cu")
		(net "CLK_100M_DB2000_CPU0_BCLK0_DN")
	)
	(segment
		(start 237.868714 -128.397254)
		(end 238.761778 -128.397254)
		(width 0.13208)
		(layer "F.Cu")
		(net "CLK_100M_DB2000_CPU0_BCLK0_DN")
	)
	(segment
		(start 240.166398 -128.717548)
		(end 240.468658 -129.019808)
		(width 0.13208)
		(layer "F.Cu")
		(net "CLK_100M_DB2000_CPU0_BCLK0_DN")
	)
	(segment
		(start 349.24238 -237.947454)
		(end 349.242634 -237.947454)
		(width 0.13208)
		(layer "F.Cu")
		(net "CLK_100M_DB2000_CPU0_BCLK0_DN")
	)
	(segment
		(start 239.535208 -128.717548)
		(end 240.166398 -128.717548)
		(width 0.13208)
		(layer "F.Cu")
		(net "CLK_100M_DB2000_CPU0_BCLK0_DN")
	)
	(segment
		(start 349.242634 -237.947454)
		(end 349.242634 -237.411514)
		(width 0.13208)
		(layer "F.Cu")
		(net "CLK_100M_DB2000_CPU0_BCLK0_DN")
	)
	(via
		(at 349.242634 -237.411514)
		(size 0.4572)
		(drill 0.2032)
		(layers "F.Cu" "B.Cu")
		(net "CLK_100M_DB2000_CPU0_BCLK0_DN")
	)
	(via
		(at 240.468658 -129.019808)
		(size 0.508)
		(drill 0.254)
		(layers "F.Cu" "B.Cu")
		(net "CLK_100M_DB2000_CPU0_BCLK0_DN")
	)
	(segment
		(start 241.210338 -134.545832)
		(end 246.168926 -146.516852)
		(width 0.13208)
		(layer "B.Cu")
		(net "CLK_100M_DB2000_CPU0_BCLK0_DN")
	)
	(segment
		(start 333.525114 -239.627156)
		(end 333.683102 -239.627156)
		(width 0.0889)
		(layer "B.Cu")
		(net "CLK_100M_DB2000_CPU0_BCLK0_DN")
	)
	(segment
		(start 240.468658 -129.019808)
		(end 240.770918 -128.717548)
		(width 0.13208)
		(layer "B.Cu")
		(net "CLK_100M_DB2000_CPU0_BCLK0_DN")
	)
	(segment
		(start 240.770918 -128.717548)
		(end 241.30508 -128.717548)
		(width 0.13208)
		(layer "B.Cu")
		(net "CLK_100M_DB2000_CPU0_BCLK0_DN")
	)
	(segment
		(start 343.87155 -237.909862)
		(end 343.886282 -237.901226)
		(width 0.0889)
		(layer "B.Cu")
		(net "CLK_100M_DB2000_CPU0_BCLK0_DN")
	)
	(segment
		(start 309.538624 -245.603014)
		(end 309.870348 -245.740428)
		(width 0.13208)
		(layer "B.Cu")
		(net "CLK_100M_DB2000_CPU0_BCLK0_DN")
	)
	(segment
		(start 349.555308 -237.411514)
		(end 349.242634 -237.411514)
		(width 0.0889)
		(layer "B.Cu")
		(net "CLK_100M_DB2000_CPU0_BCLK0_DN")
	)
	(segment
		(start 341.99195 -237.909862)
		(end 342.006682 -237.901226)
		(width 0.0889)
		(layer "B.Cu")
		(net "CLK_100M_DB2000_CPU0_BCLK0_DN")
	)
	(segment
		(start 307.318918 -243.55933)
		(end 307.595778 -243.83619)
		(width 0.13208)
		(layer "B.Cu")
		(net "CLK_100M_DB2000_CPU0_BCLK0_DN")
	)
	(segment
		(start 349.041212 -237.095538)
		(end 349.068898 -237.07979)
		(width 0.0889)
		(layer "B.Cu")
		(net "CLK_100M_DB2000_CPU0_BCLK0_DN")
	)
	(segment
		(start 275.496528 -181.123336)
		(end 288.767266 -181.123336)
		(width 0.13208)
		(layer "B.Cu")
		(net "CLK_100M_DB2000_CPU0_BCLK0_DN")
	)
	(segment
		(start 299.776642 -191.041782)
		(end 300.81728 -193.55435)
		(width 0.13208)
		(layer "B.Cu")
		(net "CLK_100M_DB2000_CPU0_BCLK0_DN")
	)
	(segment
		(start 299.630084 -190.822834)
		(end 299.776642 -191.041782)
		(width 0.13208)
		(layer "B.Cu")
		(net "CLK_100M_DB2000_CPU0_BCLK0_DN")
	)
	(segment
		(start 346.140532 -237.901226)
		(end 346.150946 -237.907322)
		(width 0.0889)
		(layer "B.Cu")
		(net "CLK_100M_DB2000_CPU0_BCLK0_DN")
	)
	(segment
		(start 304.924968 -240.989358)
		(end 306.388008 -242.452398)
		(width 0.13208)
		(layer "B.Cu")
		(net "CLK_100M_DB2000_CPU0_BCLK0_DN")
	)
	(segment
		(start 307.318918 -243.383308)
		(end 307.318918 -243.55933)
		(width 0.13208)
		(layer "B.Cu")
		(net "CLK_100M_DB2000_CPU0_BCLK0_DN")
	)
	(segment
		(start 336.357468 -237.907322)
		(end 336.367882 -237.901226)
		(width 0.0889)
		(layer "B.Cu")
		(net "CLK_100M_DB2000_CPU0_BCLK0_DN")
	)
	(segment
		(start 349.612712 -237.35411)
		(end 349.555308 -237.411514)
		(width 0.0889)
		(layer "B.Cu")
		(net "CLK_100M_DB2000_CPU0_BCLK0_DN")
	)
	(segment
		(start 338.23275 -237.909862)
		(end 338.247482 -237.901226)
		(width 0.0889)
		(layer "B.Cu")
		(net "CLK_100M_DB2000_CPU0_BCLK0_DN")
	)
	(segment
		(start 344.81135 -237.909862)
		(end 344.826082 -237.901226)
		(width 0.0889)
		(layer "B.Cu")
		(net "CLK_100M_DB2000_CPU0_BCLK0_DN")
	)
	(segment
		(start 241.55908 -129.668016)
		(end 241.210338 -131.421124)
		(width 0.13208)
		(layer "B.Cu")
		(net "CLK_100M_DB2000_CPU0_BCLK0_DN")
	)
	(segment
		(start 347.63075 -237.909862)
		(end 347.645482 -237.901226)
		(width 0.0889)
		(layer "B.Cu")
		(net "CLK_100M_DB2000_CPU0_BCLK0_DN")
	)
	(segment
		(start 241.210338 -131.421124)
		(end 241.210338 -134.545832)
		(width 0.13208)
		(layer "B.Cu")
		(net "CLK_100M_DB2000_CPU0_BCLK0_DN")
	)
	(segment
		(start 288.767266 -181.123336)
		(end 295.085516 -183.740552)
		(width 0.13208)
		(layer "B.Cu")
		(net "CLK_100M_DB2000_CPU0_BCLK0_DN")
	)
	(segment
		(start 246.168926 -146.516852)
		(end 252.38075 -159.65678)
		(width 0.13208)
		(layer "B.Cu")
		(net "CLK_100M_DB2000_CPU0_BCLK0_DN")
	)
	(segment
		(start 342.93175 -237.909862)
		(end 342.946482 -237.901226)
		(width 0.0889)
		(layer "B.Cu")
		(net "CLK_100M_DB2000_CPU0_BCLK0_DN")
	)
	(segment
		(start 241.30508 -128.717548)
		(end 241.55908 -128.971548)
		(width 0.13208)
		(layer "B.Cu")
		(net "CLK_100M_DB2000_CPU0_BCLK0_DN")
	)
	(segment
		(start 331.545438 -239.661192)
		(end 331.732382 -239.661192)
		(width 0.13208)
		(layer "B.Cu")
		(net "CLK_100M_DB2000_CPU0_BCLK0_DN")
	)
	(segment
		(start 306.388008 -242.452398)
		(end 306.388008 -242.62842)
		(width 0.13208)
		(layer "B.Cu")
		(net "CLK_100M_DB2000_CPU0_BCLK0_DN")
	)
	(segment
		(start 307.595778 -243.83619)
		(end 307.7718 -243.83619)
		(width 0.13208)
		(layer "B.Cu")
		(net "CLK_100M_DB2000_CPU0_BCLK0_DN")
	)
	(segment
		(start 300.81728 -198.01459)
		(end 301.371 -199.351392)
		(width 0.13208)
		(layer "B.Cu")
		(net "CLK_100M_DB2000_CPU0_BCLK0_DN")
	)
	(segment
		(start 349.41637 -237.07979)
		(end 349.444056 -237.095538)
		(width 0.0889)
		(layer "B.Cu")
		(net "CLK_100M_DB2000_CPU0_BCLK0_DN")
	)
	(segment
		(start 341.05215 -237.909862)
		(end 341.066882 -237.901226)
		(width 0.0889)
		(layer "B.Cu")
		(net "CLK_100M_DB2000_CPU0_BCLK0_DN")
	)
	(segment
		(start 320.534792 -242.057174)
		(end 327.575926 -242.057174)
		(width 0.13208)
		(layer "B.Cu")
		(net "CLK_100M_DB2000_CPU0_BCLK0_DN")
	)
	(segment
		(start 301.371 -239.21339)
		(end 301.889668 -239.732058)
		(width 0.13208)
		(layer "B.Cu")
		(net "CLK_100M_DB2000_CPU0_BCLK0_DN")
	)
	(segment
		(start 241.55908 -128.971548)
		(end 241.55908 -129.668016)
		(width 0.13208)
		(layer "B.Cu")
		(net "CLK_100M_DB2000_CPU0_BCLK0_DN")
	)
	(segment
		(start 330.261976 -240.944654)
		(end 331.545438 -239.661192)
		(width 0.13208)
		(layer "B.Cu")
		(net "CLK_100M_DB2000_CPU0_BCLK0_DN")
	)
	(segment
		(start 348.867984 -237.425738)
		(end 348.867984 -237.411514)
		(width 0.0889)
		(layer "B.Cu")
		(net "CLK_100M_DB2000_CPU0_BCLK0_DN")
	)
	(segment
		(start 337.29295 -237.909862)
		(end 337.307682 -237.901226)
		(width 0.0889)
		(layer "B.Cu")
		(net "CLK_100M_DB2000_CPU0_BCLK0_DN")
	)
	(segment
		(start 297.83659 -186.491626)
		(end 299.630084 -190.822834)
		(width 0.13208)
		(layer "B.Cu")
		(net "CLK_100M_DB2000_CPU0_BCLK0_DN")
	)
	(segment
		(start 306.388008 -242.62842)
		(end 306.664868 -242.90528)
		(width 0.13208)
		(layer "B.Cu")
		(net "CLK_100M_DB2000_CPU0_BCLK0_DN")
	)
	(segment
		(start 301.889668 -239.732058)
		(end 304.924968 -240.989358)
		(width 0.13208)
		(layer "B.Cu")
		(net "CLK_100M_DB2000_CPU0_BCLK0_DN")
	)
	(segment
		(start 272.6817 -179.957476)
		(end 275.496528 -181.123336)
		(width 0.13208)
		(layer "B.Cu")
		(net "CLK_100M_DB2000_CPU0_BCLK0_DN")
	)
	(segment
		(start 339.177122 -237.907322)
		(end 339.187536 -237.901226)
		(width 0.0889)
		(layer "B.Cu")
		(net "CLK_100M_DB2000_CPU0_BCLK0_DN")
	)
	(segment
		(start 333.524606 -239.626648)
		(end 333.525114 -239.627156)
		(width 0.0889)
		(layer "B.Cu")
		(net "CLK_100M_DB2000_CPU0_BCLK0_DN")
	)
	(segment
		(start 300.81728 -193.55435)
		(end 300.81728 -198.01459)
		(width 0.13208)
		(layer "B.Cu")
		(net "CLK_100M_DB2000_CPU0_BCLK0_DN")
	)
	(segment
		(start 306.664868 -242.90528)
		(end 306.84089 -242.90528)
		(width 0.13208)
		(layer "B.Cu")
		(net "CLK_100M_DB2000_CPU0_BCLK0_DN")
	)
	(segment
		(start 307.7718 -243.83619)
		(end 309.538624 -245.603014)
		(width 0.13208)
		(layer "B.Cu")
		(net "CLK_100M_DB2000_CPU0_BCLK0_DN")
	)
	(segment
		(start 313.693048 -243.589302)
		(end 314.488322 -243.259864)
		(width 0.13208)
		(layer "B.Cu")
		(net "CLK_100M_DB2000_CPU0_BCLK0_DN")
	)
	(segment
		(start 339.561932 -237.901226)
		(end 339.572346 -237.907322)
		(width 0.0889)
		(layer "B.Cu")
		(net "CLK_100M_DB2000_CPU0_BCLK0_DN")
	)
	(segment
		(start 331.732382 -239.661192)
		(end 331.75448 -239.661192)
		(width 0.0889)
		(layer "B.Cu")
		(net "CLK_100M_DB2000_CPU0_BCLK0_DN")
	)
	(segment
		(start 312.190892 -245.091458)
		(end 313.693048 -243.589302)
		(width 0.13208)
		(layer "B.Cu")
		(net "CLK_100M_DB2000_CPU0_BCLK0_DN")
	)
	(segment
		(start 310.623712 -245.740428)
		(end 312.190892 -245.091458)
		(width 0.13208)
		(layer "B.Cu")
		(net "CLK_100M_DB2000_CPU0_BCLK0_DN")
	)
	(segment
		(start 252.38075 -159.65678)
		(end 272.6817 -179.957476)
		(width 0.13208)
		(layer "B.Cu")
		(net "CLK_100M_DB2000_CPU0_BCLK0_DN")
	)
	(segment
		(start 345.755722 -237.907322)
		(end 345.766136 -237.901226)
		(width 0.0889)
		(layer "B.Cu")
		(net "CLK_100M_DB2000_CPU0_BCLK0_DN")
	)
	(segment
		(start 309.870348 -245.740428)
		(end 310.623712 -245.740428)
		(width 0.13208)
		(layer "B.Cu")
		(net "CLK_100M_DB2000_CPU0_BCLK0_DN")
	)
	(segment
		(start 301.371 -199.351392)
		(end 301.371 -239.21339)
		(width 0.13208)
		(layer "B.Cu")
		(net "CLK_100M_DB2000_CPU0_BCLK0_DN")
	)
	(segment
		(start 333.683102 -239.627156)
		(end 335.350104 -237.960154)
		(width 0.0889)
		(layer "B.Cu")
		(net "CLK_100M_DB2000_CPU0_BCLK0_DN")
	)
	(segment
		(start 314.488322 -243.259864)
		(end 320.534792 -242.057174)
		(width 0.13208)
		(layer "B.Cu")
		(net "CLK_100M_DB2000_CPU0_BCLK0_DN")
	)
	(segment
		(start 295.085516 -183.740552)
		(end 297.83659 -186.491626)
		(width 0.13208)
		(layer "B.Cu")
		(net "CLK_100M_DB2000_CPU0_BCLK0_DN")
	)
	(segment
		(start 306.84089 -242.90528)
		(end 307.318918 -243.383308)
		(width 0.13208)
		(layer "B.Cu")
		(net "CLK_100M_DB2000_CPU0_BCLK0_DN")
	)
	(segment
		(start 327.575926 -242.057174)
		(end 330.261976 -240.944654)
		(width 0.13208)
		(layer "B.Cu")
		(net "CLK_100M_DB2000_CPU0_BCLK0_DN")
	)
	(segment
		(start 331.75448 -239.661192)
		(end 331.789024 -239.626648)
		(width 0.0889)
		(layer "B.Cu")
		(net "CLK_100M_DB2000_CPU0_BCLK0_DN")
	)
	(segment
		(start 331.789024 -239.626648)
		(end 333.524606 -239.626648)
		(width 0.0889)
		(layer "B.Cu")
		(net "CLK_100M_DB2000_CPU0_BCLK0_DN")
	)
	(arc
		(start 335.802732 -237.901226)
		(mid 336.079291 -237.976935)
		(end 336.357468 -237.907322)
		(width 0.0889)
		(layer "B.Cu")
		(net "CLK_100M_DB2000_CPU0_BCLK0_DN")
	)
	(arc
		(start 341.066882 -237.901226)
		(mid 341.25408 -237.851083)
		(end 341.441278 -237.901226)
		(width 0.0889)
		(layer "B.Cu")
		(net "CLK_100M_DB2000_CPU0_BCLK0_DN")
	)
	(arc
		(start 345.200478 -237.901226)
		(mid 345.477291 -237.977062)
		(end 345.755722 -237.907322)
		(width 0.0889)
		(layer "B.Cu")
		(net "CLK_100M_DB2000_CPU0_BCLK0_DN")
	)
	(arc
		(start 344.260678 -237.901226)
		(mid 344.534907 -237.977151)
		(end 344.81135 -237.909862)
		(width 0.0889)
		(layer "B.Cu")
		(net "CLK_100M_DB2000_CPU0_BCLK0_DN")
	)
	(arc
		(start 338.247482 -237.901226)
		(mid 338.43468 -237.851083)
		(end 338.621878 -237.901226)
		(width 0.0889)
		(layer "B.Cu")
		(net "CLK_100M_DB2000_CPU0_BCLK0_DN")
	)
	(arc
		(start 335.428336 -237.901226)
		(mid 335.615534 -237.851083)
		(end 335.802732 -237.901226)
		(width 0.0889)
		(layer "B.Cu")
		(net "CLK_100M_DB2000_CPU0_BCLK0_DN")
	)
	(arc
		(start 347.080078 -237.901226)
		(mid 347.354307 -237.977151)
		(end 347.63075 -237.909862)
		(width 0.0889)
		(layer "B.Cu")
		(net "CLK_100M_DB2000_CPU0_BCLK0_DN")
	)
	(arc
		(start 342.946482 -237.901226)
		(mid 343.13368 -237.851083)
		(end 343.320878 -237.901226)
		(width 0.0889)
		(layer "B.Cu")
		(net "CLK_100M_DB2000_CPU0_BCLK0_DN")
	)
	(arc
		(start 349.444056 -237.095538)
		(mid 349.556215 -237.206661)
		(end 349.612712 -237.35411)
		(width 0.0889)
		(layer "B.Cu")
		(net "CLK_100M_DB2000_CPU0_BCLK0_DN")
	)
	(arc
		(start 344.826082 -237.901226)
		(mid 345.01328 -237.851083)
		(end 345.200478 -237.901226)
		(width 0.0889)
		(layer "B.Cu")
		(net "CLK_100M_DB2000_CPU0_BCLK0_DN")
	)
	(arc
		(start 346.705682 -237.901226)
		(mid 346.89288 -237.851083)
		(end 347.080078 -237.901226)
		(width 0.0889)
		(layer "B.Cu")
		(net "CLK_100M_DB2000_CPU0_BCLK0_DN")
	)
	(arc
		(start 340.501478 -237.901226)
		(mid 340.775707 -237.977151)
		(end 341.05215 -237.909862)
		(width 0.0889)
		(layer "B.Cu")
		(net "CLK_100M_DB2000_CPU0_BCLK0_DN")
	)
	(arc
		(start 337.307682 -237.901226)
		(mid 337.49488 -237.851083)
		(end 337.682078 -237.901226)
		(width 0.0889)
		(layer "B.Cu")
		(net "CLK_100M_DB2000_CPU0_BCLK0_DN")
	)
	(arc
		(start 340.127082 -237.901226)
		(mid 340.31428 -237.851083)
		(end 340.501478 -237.901226)
		(width 0.0889)
		(layer "B.Cu")
		(net "CLK_100M_DB2000_CPU0_BCLK0_DN")
	)
	(arc
		(start 342.006682 -237.901226)
		(mid 342.19388 -237.851083)
		(end 342.381078 -237.901226)
		(width 0.0889)
		(layer "B.Cu")
		(net "CLK_100M_DB2000_CPU0_BCLK0_DN")
	)
	(arc
		(start 339.187536 -237.901226)
		(mid 339.374734 -237.851083)
		(end 339.561932 -237.901226)
		(width 0.0889)
		(layer "B.Cu")
		(net "CLK_100M_DB2000_CPU0_BCLK0_DN")
	)
	(arc
		(start 346.150946 -237.907322)
		(mid 346.429124 -237.977014)
		(end 346.705682 -237.901226)
		(width 0.0889)
		(layer "B.Cu")
		(net "CLK_100M_DB2000_CPU0_BCLK0_DN")
	)
	(arc
		(start 338.621878 -237.901226)
		(mid 338.898691 -237.977062)
		(end 339.177122 -237.907322)
		(width 0.0889)
		(layer "B.Cu")
		(net "CLK_100M_DB2000_CPU0_BCLK0_DN")
	)
	(arc
		(start 343.320878 -237.901226)
		(mid 343.595107 -237.977151)
		(end 343.87155 -237.909862)
		(width 0.0889)
		(layer "B.Cu")
		(net "CLK_100M_DB2000_CPU0_BCLK0_DN")
	)
	(arc
		(start 345.766136 -237.901226)
		(mid 345.953334 -237.851083)
		(end 346.140532 -237.901226)
		(width 0.0889)
		(layer "B.Cu")
		(net "CLK_100M_DB2000_CPU0_BCLK0_DN")
	)
	(arc
		(start 343.886282 -237.901226)
		(mid 344.07348 -237.851083)
		(end 344.260678 -237.901226)
		(width 0.0889)
		(layer "B.Cu")
		(net "CLK_100M_DB2000_CPU0_BCLK0_DN")
	)
	(arc
		(start 348.867984 -237.411514)
		(mid 348.914123 -237.231329)
		(end 349.041212 -237.095538)
		(width 0.0889)
		(layer "B.Cu")
		(net "CLK_100M_DB2000_CPU0_BCLK0_DN")
	)
	(arc
		(start 336.742278 -237.901226)
		(mid 337.016507 -237.977151)
		(end 337.29295 -237.909862)
		(width 0.0889)
		(layer "B.Cu")
		(net "CLK_100M_DB2000_CPU0_BCLK0_DN")
	)
	(arc
		(start 341.441278 -237.901226)
		(mid 341.715507 -237.977151)
		(end 341.99195 -237.909862)
		(width 0.0889)
		(layer "B.Cu")
		(net "CLK_100M_DB2000_CPU0_BCLK0_DN")
	)
	(arc
		(start 337.682078 -237.901226)
		(mid 337.956307 -237.977151)
		(end 338.23275 -237.909862)
		(width 0.0889)
		(layer "B.Cu")
		(net "CLK_100M_DB2000_CPU0_BCLK0_DN")
	)
	(arc
		(start 349.068898 -237.07979)
		(mid 349.242634 -237.033652)
		(end 349.41637 -237.07979)
		(width 0.0889)
		(layer "B.Cu")
		(net "CLK_100M_DB2000_CPU0_BCLK0_DN")
	)
	(arc
		(start 335.350104 -237.960154)
		(mid 335.387295 -237.928136)
		(end 335.428336 -237.901226)
		(width 0.0889)
		(layer "B.Cu")
		(net "CLK_100M_DB2000_CPU0_BCLK0_DN")
	)
	(arc
		(start 347.645482 -237.901226)
		(mid 347.83268 -237.851083)
		(end 348.019878 -237.901226)
		(width 0.0889)
		(layer "B.Cu")
		(net "CLK_100M_DB2000_CPU0_BCLK0_DN")
	)
	(arc
		(start 339.572346 -237.907322)
		(mid 339.850524 -237.977014)
		(end 340.127082 -237.901226)
		(width 0.0889)
		(layer "B.Cu")
		(net "CLK_100M_DB2000_CPU0_BCLK0_DN")
	)
	(arc
		(start 348.019878 -237.901226)
		(mid 348.579356 -237.904887)
		(end 348.867984 -237.425738)
		(width 0.0889)
		(layer "B.Cu")
		(net "CLK_100M_DB2000_CPU0_BCLK0_DN")
	)
	(arc
		(start 336.367882 -237.901226)
		(mid 336.55508 -237.851083)
		(end 336.742278 -237.901226)
		(width 0.0889)
		(layer "B.Cu")
		(net "CLK_100M_DB2000_CPU0_BCLK0_DN")
	)
	(arc
		(start 342.381078 -237.901226)
		(mid 342.655307 -237.977151)
		(end 342.93175 -237.909862)
		(width 0.0889)
		(layer "B.Cu")
		(net "CLK_100M_DB2000_CPU0_BCLK0_DN")
	)
	(segment
		(start 257.571494 -107.233974)
		(end 257.571494 -107.359196)
		(width 0.13208)
		(layer "F.Cu")
		(net "CLK_100M_CK440_PCH_EXTCLK_R_DP")
	)
	(segment
		(start 257.256534 -106.919014)
		(end 257.571494 -107.233974)
		(width 0.13208)
		(layer "F.Cu")
		(net "CLK_100M_CK440_PCH_EXTCLK_R_DP")
	)
	(segment
		(start 256.554478 -103.775002)
		(end 256.554478 -104.534462)
		(width 0.13208)
		(layer "F.Cu")
		(net "CLK_100M_CK440_PCH_EXTCLK_R_DP")
	)
	(segment
		(start 256.554478 -104.534462)
		(end 257.256534 -105.236518)
		(width 0.13208)
		(layer "F.Cu")
		(net "CLK_100M_CK440_PCH_EXTCLK_R_DP")
	)
	(segment
		(start 257.256534 -105.236518)
		(end 257.256534 -106.919014)
		(width 0.13208)
		(layer "F.Cu")
		(net "CLK_100M_CK440_PCH_EXTCLK_R_DP")
	)
	(segment
		(start 256.432812 -103.438198)
		(end 256.432812 -103.653336)
		(width 0.13208)
		(layer "F.Cu")
		(net "CLK_100M_CK440_PCH_EXTCLK_R_DP")
	)
	(segment
		(start 257.571494 -107.359196)
		(end 257.176524 -107.754166)
		(width 0.13208)
		(layer "F.Cu")
		(net "CLK_100M_CK440_PCH_EXTCLK_R_DP")
	)
	(segment
		(start 256.432812 -103.653336)
		(end 256.554478 -103.775002)
		(width 0.13208)
		(layer "F.Cu")
		(net "CLK_100M_CK440_PCH_EXTCLK_R_DP")
	)
	(segment
		(start 257.830574 -107.392216)
		(end 258.192524 -107.754166)
		(width 0.13208)
		(layer "F.Cu")
		(net "CLK_100M_CK440_PCH_EXTCLK_R_DN")
	)
	(segment
		(start 257.515614 -105.129076)
		(end 257.515614 -106.811572)
		(width 0.13208)
		(layer "F.Cu")
		(net "CLK_100M_CK440_PCH_EXTCLK_R_DN")
	)
	(segment
		(start 256.932684 -103.438198)
		(end 256.932684 -103.655368)
		(width 0.13208)
		(layer "F.Cu")
		(net "CLK_100M_CK440_PCH_EXTCLK_R_DN")
	)
	(segment
		(start 257.830574 -107.126532)
		(end 257.830574 -107.392216)
		(width 0.13208)
		(layer "F.Cu")
		(net "CLK_100M_CK440_PCH_EXTCLK_R_DN")
	)
	(segment
		(start 256.932684 -103.655368)
		(end 256.813558 -103.774494)
		(width 0.13208)
		(layer "F.Cu")
		(net "CLK_100M_CK440_PCH_EXTCLK_R_DN")
	)
	(segment
		(start 257.515614 -106.811572)
		(end 257.830574 -107.126532)
		(width 0.13208)
		(layer "F.Cu")
		(net "CLK_100M_CK440_PCH_EXTCLK_R_DN")
	)
	(segment
		(start 256.813558 -103.774494)
		(end 256.813558 -104.42702)
		(width 0.13208)
		(layer "F.Cu")
		(net "CLK_100M_CK440_PCH_EXTCLK_R_DN")
	)
	(segment
		(start 256.813558 -104.42702)
		(end 257.515614 -105.129076)
		(width 0.13208)
		(layer "F.Cu")
		(net "CLK_100M_CK440_PCH_EXTCLK_R_DN")
	)
	(segment
		(start 335.333848 -63.063628)
		(end 335.234788 -62.964568)
		(width 0.0889)
		(layer "F.Cu")
		(net "CLK_100M_CK440_PCH_EXTCLK_DP")
	)
	(segment
		(start 335.234788 -61.679328)
		(end 335.360264 -61.553852)
		(width 0.0889)
		(layer "F.Cu")
		(net "CLK_100M_CK440_PCH_EXTCLK_DP")
	)
	(segment
		(start 332.963012 -67.278758)
		(end 332.963012 -66.623438)
		(width 0.0889)
		(layer "F.Cu")
		(net "CLK_100M_CK440_PCH_EXTCLK_DP")
	)
	(segment
		(start 335.333848 -62.133988)
		(end 335.333848 -61.956188)
		(width 0.0889)
		(layer "F.Cu")
		(net "CLK_100M_CK440_PCH_EXTCLK_DP")
	)
	(segment
		(start 335.234788 -63.737744)
		(end 335.234788 -63.340488)
		(width 0.0889)
		(layer "F.Cu")
		(net "CLK_100M_CK440_PCH_EXTCLK_DP")
	)
	(segment
		(start 334.325976 -64.787018)
		(end 334.325976 -64.646556)
		(width 0.0889)
		(layer "F.Cu")
		(net "CLK_100M_CK440_PCH_EXTCLK_DP")
	)
	(segment
		(start 333.062072 -66.346578)
		(end 332.963012 -66.247518)
		(width 0.0889)
		(layer "F.Cu")
		(net "CLK_100M_CK440_PCH_EXTCLK_DP")
	)
	(segment
		(start 336.399378 -60.336938)
		(end 336.498438 -60.237878)
		(width 0.0889)
		(layer "F.Cu")
		(net "CLK_100M_CK440_PCH_EXTCLK_DP")
	)
	(segment
		(start 335.109312 -64.003682)
		(end 335.109312 -63.86322)
		(width 0.0889)
		(layer "F.Cu")
		(net "CLK_100M_CK440_PCH_EXTCLK_DP")
	)
	(segment
		(start 335.234788 -62.786768)
		(end 335.333848 -62.687708)
		(width 0.0889)
		(layer "F.Cu")
		(net "CLK_100M_CK440_PCH_EXTCLK_DP")
	)
	(segment
		(start 333.934308 -65.038224)
		(end 334.059784 -64.912748)
		(width 0.0889)
		(layer "F.Cu")
		(net "CLK_100M_CK440_PCH_EXTCLK_DP")
	)
	(segment
		(start 336.018124 -61.036454)
		(end 336.018124 -60.895992)
		(width 0.0889)
		(layer "F.Cu")
		(net "CLK_100M_CK440_PCH_EXTCLK_DP")
	)
	(segment
		(start 334.717644 -64.254888)
		(end 334.84312 -64.129412)
		(width 0.0889)
		(layer "F.Cu")
		(net "CLK_100M_CK440_PCH_EXTCLK_DP")
	)
	(segment
		(start 336.399378 -59.961018)
		(end 336.399378 -59.130184)
		(width 0.0889)
		(layer "F.Cu")
		(net "CLK_100M_CK440_PCH_EXTCLK_DP")
	)
	(segment
		(start 334.84312 -64.129412)
		(end 334.983582 -64.129412)
		(width 0.0889)
		(layer "F.Cu")
		(net "CLK_100M_CK440_PCH_EXTCLK_DP")
	)
	(segment
		(start 335.751932 -61.162184)
		(end 335.892394 -61.162184)
		(width 0.0889)
		(layer "F.Cu")
		(net "CLK_100M_CK440_PCH_EXTCLK_DP")
	)
	(segment
		(start 335.234788 -62.964568)
		(end 335.234788 -62.786768)
		(width 0.0889)
		(layer "F.Cu")
		(net "CLK_100M_CK440_PCH_EXTCLK_DP")
	)
	(segment
		(start 333.282544 -72.376792)
		(end 332.997302 -72.09155)
		(width 0.13208)
		(layer "F.Cu")
		(net "CLK_100M_CK440_PCH_EXTCLK_DP")
	)
	(segment
		(start 332.963012 -66.247518)
		(end 332.963012 -66.00952)
		(width 0.0889)
		(layer "F.Cu")
		(net "CLK_100M_CK440_PCH_EXTCLK_DP")
	)
	(segment
		(start 334.325976 -64.646556)
		(end 334.451452 -64.52108)
		(width 0.0889)
		(layer "F.Cu")
		(net "CLK_100M_CK440_PCH_EXTCLK_DP")
	)
	(segment
		(start 333.54264 -65.570354)
		(end 333.54264 -65.429892)
		(width 0.0889)
		(layer "F.Cu")
		(net "CLK_100M_CK440_PCH_EXTCLK_DP")
	)
	(segment
		(start 332.963012 -66.623438)
		(end 333.062072 -66.524378)
		(width 0.0889)
		(layer "F.Cu")
		(net "CLK_100M_CK440_PCH_EXTCLK_DP")
	)
	(segment
		(start 332.997302 -67.335146)
		(end 332.997302 -67.313048)
		(width 0.0889)
		(layer "F.Cu")
		(net "CLK_100M_CK440_PCH_EXTCLK_DP")
	)
	(segment
		(start 334.200246 -64.912748)
		(end 334.325976 -64.787018)
		(width 0.0889)
		(layer "F.Cu")
		(net "CLK_100M_CK440_PCH_EXTCLK_DP")
	)
	(segment
		(start 257.58394 -108.961682)
		(end 257.58394 -109.636306)
		(width 0.13208)
		(layer "F.Cu")
		(net "CLK_100M_CK440_PCH_EXTCLK_DP")
	)
	(segment
		(start 333.276448 -65.696084)
		(end 333.41691 -65.696084)
		(width 0.0889)
		(layer "F.Cu")
		(net "CLK_100M_CK440_PCH_EXTCLK_DP")
	)
	(segment
		(start 334.451452 -64.52108)
		(end 334.591914 -64.52108)
		(width 0.0889)
		(layer "F.Cu")
		(net "CLK_100M_CK440_PCH_EXTCLK_DP")
	)
	(segment
		(start 333.668116 -65.304416)
		(end 333.808578 -65.304416)
		(width 0.0889)
		(layer "F.Cu")
		(net "CLK_100M_CK440_PCH_EXTCLK_DP")
	)
	(segment
		(start 333.934308 -65.178686)
		(end 333.934308 -65.038224)
		(width 0.0889)
		(layer "F.Cu")
		(net "CLK_100M_CK440_PCH_EXTCLK_DP")
	)
	(segment
		(start 332.963012 -66.00952)
		(end 333.276448 -65.696084)
		(width 0.0889)
		(layer "F.Cu")
		(net "CLK_100M_CK440_PCH_EXTCLK_DP")
	)
	(segment
		(start 257.58394 -109.636306)
		(end 257.266694 -109.953552)
		(width 0.13208)
		(layer "F.Cu")
		(net "CLK_100M_CK440_PCH_EXTCLK_DP")
	)
	(segment
		(start 335.892394 -61.162184)
		(end 336.018124 -61.036454)
		(width 0.0889)
		(layer "F.Cu")
		(net "CLK_100M_CK440_PCH_EXTCLK_DP")
	)
	(segment
		(start 333.808578 -65.304416)
		(end 333.934308 -65.178686)
		(width 0.0889)
		(layer "F.Cu")
		(net "CLK_100M_CK440_PCH_EXTCLK_DP")
	)
	(segment
		(start 335.333848 -61.956188)
		(end 335.234788 -61.857128)
		(width 0.0889)
		(layer "F.Cu")
		(net "CLK_100M_CK440_PCH_EXTCLK_DP")
	)
	(segment
		(start 336.018124 -60.895992)
		(end 336.399378 -60.514738)
		(width 0.0889)
		(layer "F.Cu")
		(net "CLK_100M_CK440_PCH_EXTCLK_DP")
	)
	(segment
		(start 335.109312 -63.86322)
		(end 335.234788 -63.737744)
		(width 0.0889)
		(layer "F.Cu")
		(net "CLK_100M_CK440_PCH_EXTCLK_DP")
	)
	(segment
		(start 335.333848 -62.687708)
		(end 335.333848 -62.509908)
		(width 0.0889)
		(layer "F.Cu")
		(net "CLK_100M_CK440_PCH_EXTCLK_DP")
	)
	(segment
		(start 333.41691 -65.696084)
		(end 333.54264 -65.570354)
		(width 0.0889)
		(layer "F.Cu")
		(net "CLK_100M_CK440_PCH_EXTCLK_DP")
	)
	(segment
		(start 334.059784 -64.912748)
		(end 334.200246 -64.912748)
		(width 0.0889)
		(layer "F.Cu")
		(net "CLK_100M_CK440_PCH_EXTCLK_DP")
	)
	(segment
		(start 335.333848 -62.509908)
		(end 335.234788 -62.410848)
		(width 0.0889)
		(layer "F.Cu")
		(net "CLK_100M_CK440_PCH_EXTCLK_DP")
	)
	(segment
		(start 335.626456 -61.428122)
		(end 335.626456 -61.28766)
		(width 0.0889)
		(layer "F.Cu")
		(net "CLK_100M_CK440_PCH_EXTCLK_DP")
	)
	(segment
		(start 336.498438 -60.060078)
		(end 336.399378 -59.961018)
		(width 0.0889)
		(layer "F.Cu")
		(net "CLK_100M_CK440_PCH_EXTCLK_DP")
	)
	(segment
		(start 332.997302 -67.313048)
		(end 332.963012 -67.278758)
		(width 0.0889)
		(layer "F.Cu")
		(net "CLK_100M_CK440_PCH_EXTCLK_DP")
	)
	(segment
		(start 336.399378 -60.514738)
		(end 336.399378 -60.336938)
		(width 0.0889)
		(layer "F.Cu")
		(net "CLK_100M_CK440_PCH_EXTCLK_DP")
	)
	(segment
		(start 335.360264 -61.553852)
		(end 335.500726 -61.553852)
		(width 0.0889)
		(layer "F.Cu")
		(net "CLK_100M_CK440_PCH_EXTCLK_DP")
	)
	(segment
		(start 333.54264 -65.429892)
		(end 333.668116 -65.304416)
		(width 0.0889)
		(layer "F.Cu")
		(net "CLK_100M_CK440_PCH_EXTCLK_DP")
	)
	(segment
		(start 332.997302 -72.09155)
		(end 332.997302 -67.335146)
		(width 0.13208)
		(layer "F.Cu")
		(net "CLK_100M_CK440_PCH_EXTCLK_DP")
	)
	(segment
		(start 335.234788 -63.340488)
		(end 335.333848 -63.241428)
		(width 0.0889)
		(layer "F.Cu")
		(net "CLK_100M_CK440_PCH_EXTCLK_DP")
	)
	(segment
		(start 335.500726 -61.553852)
		(end 335.626456 -61.428122)
		(width 0.0889)
		(layer "F.Cu")
		(net "CLK_100M_CK440_PCH_EXTCLK_DP")
	)
	(segment
		(start 335.626456 -61.28766)
		(end 335.751932 -61.162184)
		(width 0.0889)
		(layer "F.Cu")
		(net "CLK_100M_CK440_PCH_EXTCLK_DP")
	)
	(segment
		(start 335.333848 -63.241428)
		(end 335.333848 -63.063628)
		(width 0.0889)
		(layer "F.Cu")
		(net "CLK_100M_CK440_PCH_EXTCLK_DP")
	)
	(segment
		(start 335.234788 -62.410848)
		(end 335.234788 -62.233048)
		(width 0.0889)
		(layer "F.Cu")
		(net "CLK_100M_CK440_PCH_EXTCLK_DP")
	)
	(segment
		(start 334.717644 -64.39535)
		(end 334.717644 -64.254888)
		(width 0.0889)
		(layer "F.Cu")
		(net "CLK_100M_CK440_PCH_EXTCLK_DP")
	)
	(segment
		(start 335.234788 -61.857128)
		(end 335.234788 -61.679328)
		(width 0.0889)
		(layer "F.Cu")
		(net "CLK_100M_CK440_PCH_EXTCLK_DP")
	)
	(segment
		(start 333.062072 -66.524378)
		(end 333.062072 -66.346578)
		(width 0.0889)
		(layer "F.Cu")
		(net "CLK_100M_CK440_PCH_EXTCLK_DP")
	)
	(segment
		(start 336.498438 -60.237878)
		(end 336.498438 -60.060078)
		(width 0.0889)
		(layer "F.Cu")
		(net "CLK_100M_CK440_PCH_EXTCLK_DP")
	)
	(segment
		(start 336.399378 -59.130184)
		(end 336.399632 -59.12993)
		(width 0.0889)
		(layer "F.Cu")
		(net "CLK_100M_CK440_PCH_EXTCLK_DP")
	)
	(segment
		(start 335.234788 -62.233048)
		(end 335.333848 -62.133988)
		(width 0.0889)
		(layer "F.Cu")
		(net "CLK_100M_CK440_PCH_EXTCLK_DP")
	)
	(segment
		(start 334.591914 -64.52108)
		(end 334.717644 -64.39535)
		(width 0.0889)
		(layer "F.Cu")
		(net "CLK_100M_CK440_PCH_EXTCLK_DP")
	)
	(segment
		(start 336.399632 -59.12993)
		(end 336.399632 -58.850276)
		(width 0.0889)
		(layer "F.Cu")
		(net "CLK_100M_CK440_PCH_EXTCLK_DP")
	)
	(segment
		(start 257.176524 -108.554266)
		(end 257.58394 -108.961682)
		(width 0.13208)
		(layer "F.Cu")
		(net "CLK_100M_CK440_PCH_EXTCLK_DP")
	)
	(segment
		(start 334.983582 -64.129412)
		(end 335.109312 -64.003682)
		(width 0.0889)
		(layer "F.Cu")
		(net "CLK_100M_CK440_PCH_EXTCLK_DP")
	)
	(via
		(at 257.266694 -109.953552)
		(size 0.508)
		(drill 0.254)
		(layers "F.Cu" "B.Cu")
		(net "CLK_100M_CK440_PCH_EXTCLK_DP")
	)
	(via
		(at 333.282544 -72.376792)
		(size 0.508)
		(drill 0.254)
		(layers "F.Cu" "B.Cu")
		(net "CLK_100M_CK440_PCH_EXTCLK_DP")
	)
	(segment
		(start 340.33587 -76.752196)
		(end 340.428834 -76.92644)
		(width 0.14732)
		(layer "In4.Cu")
		(net "CLK_100M_CK440_PCH_EXTCLK_DP")
	)
	(segment
		(start 336.28711 -71.865998)
		(end 336.42681 -71.726298)
		(width 0.14732)
		(layer "In4.Cu")
		(net "CLK_100M_CK440_PCH_EXTCLK_DP")
	)
	(segment
		(start 335.41081 -71.726298)
		(end 335.77911 -71.726298)
		(width 0.14732)
		(layer "In4.Cu")
		(net "CLK_100M_CK440_PCH_EXTCLK_DP")
	)
	(segment
		(start 340.443058 -76.39939)
		(end 340.33587 -76.752196)
		(width 0.14732)
		(layer "In4.Cu")
		(net "CLK_100M_CK440_PCH_EXTCLK_DP")
	)
	(segment
		(start 332.987904 -72.082152)
		(end 332.987904 -71.873618)
		(width 0.14732)
		(layer "In4.Cu")
		(net "CLK_100M_CK440_PCH_EXTCLK_DP")
	)
	(segment
		(start 335.91881 -71.865998)
		(end 336.28711 -71.865998)
		(width 0.14732)
		(layer "In4.Cu")
		(net "CLK_100M_CK440_PCH_EXTCLK_DP")
	)
	(segment
		(start 335.27111 -71.865998)
		(end 335.41081 -71.726298)
		(width 0.14732)
		(layer "In4.Cu")
		(net "CLK_100M_CK440_PCH_EXTCLK_DP")
	)
	(segment
		(start 341.15248 -73.193148)
		(end 341.15248 -74.109326)
		(width 0.14732)
		(layer "In4.Cu")
		(net "CLK_100M_CK440_PCH_EXTCLK_DP")
	)
	(segment
		(start 339.514688 -79.933292)
		(end 339.219032 -80.90662)
		(width 0.14732)
		(layer "In4.Cu")
		(net "CLK_100M_CK440_PCH_EXTCLK_DP")
	)
	(segment
		(start 340.428834 -76.92644)
		(end 340.270592 -77.447394)
		(width 0.14732)
		(layer "In4.Cu")
		(net "CLK_100M_CK440_PCH_EXTCLK_DP")
	)
	(segment
		(start 335.77911 -71.726298)
		(end 335.91881 -71.865998)
		(width 0.14732)
		(layer "In4.Cu")
		(net "CLK_100M_CK440_PCH_EXTCLK_DP")
	)
	(segment
		(start 333.88681 -71.865998)
		(end 334.25511 -71.865998)
		(width 0.14732)
		(layer "In4.Cu")
		(net "CLK_100M_CK440_PCH_EXTCLK_DP")
	)
	(segment
		(start 334.39481 -71.726298)
		(end 334.76311 -71.726298)
		(width 0.14732)
		(layer "In4.Cu")
		(net "CLK_100M_CK440_PCH_EXTCLK_DP")
	)
	(segment
		(start 337.02625 -71.726298)
		(end 337.16595 -71.865998)
		(width 0.14732)
		(layer "In4.Cu")
		(net "CLK_100M_CK440_PCH_EXTCLK_DP")
	)
	(segment
		(start 338.856574 -71.726298)
		(end 340.272116 -72.312784)
		(width 0.14732)
		(layer "In4.Cu")
		(net "CLK_100M_CK440_PCH_EXTCLK_DP")
	)
	(segment
		(start 257.561334 -109.658912)
		(end 257.266694 -109.953552)
		(width 0.14732)
		(layer "In4.Cu")
		(net "CLK_100M_CK440_PCH_EXTCLK_DP")
	)
	(segment
		(start 336.605372 -84.25942)
		(end 328.09815 -85.951568)
		(width 0.14732)
		(layer "In4.Cu")
		(net "CLK_100M_CK440_PCH_EXTCLK_DP")
	)
	(segment
		(start 340.896448 -75.388724)
		(end 340.617556 -76.306426)
		(width 0.14732)
		(layer "In4.Cu")
		(net "CLK_100M_CK440_PCH_EXTCLK_DP")
	)
	(segment
		(start 339.219032 -80.90662)
		(end 338.296504 -83.129374)
		(width 0.14732)
		(layer "In4.Cu")
		(net "CLK_100M_CK440_PCH_EXTCLK_DP")
	)
	(segment
		(start 339.421724 -79.759048)
		(end 339.514688 -79.933292)
		(width 0.14732)
		(layer "In4.Cu")
		(net "CLK_100M_CK440_PCH_EXTCLK_DP")
	)
	(segment
		(start 341.15248 -74.109326)
		(end 340.896448 -75.388724)
		(width 0.14732)
		(layer "In4.Cu")
		(net "CLK_100M_CK440_PCH_EXTCLK_DP")
	)
	(segment
		(start 337.67395 -71.726298)
		(end 338.856574 -71.726298)
		(width 0.14732)
		(layer "In4.Cu")
		(net "CLK_100M_CK440_PCH_EXTCLK_DP")
	)
	(segment
		(start 334.25511 -71.865998)
		(end 334.39481 -71.726298)
		(width 0.14732)
		(layer "In4.Cu")
		(net "CLK_100M_CK440_PCH_EXTCLK_DP")
	)
	(segment
		(start 340.617556 -76.306426)
		(end 340.443058 -76.39939)
		(width 0.14732)
		(layer "In4.Cu")
		(net "CLK_100M_CK440_PCH_EXTCLK_DP")
	)
	(segment
		(start 340.272116 -72.312784)
		(end 341.15248 -73.193148)
		(width 0.14732)
		(layer "In4.Cu")
		(net "CLK_100M_CK440_PCH_EXTCLK_DP")
	)
	(segment
		(start 338.29625 -83.129628)
		(end 336.605372 -84.25942)
		(width 0.14732)
		(layer "In4.Cu")
		(net "CLK_100M_CK440_PCH_EXTCLK_DP")
	)
	(segment
		(start 334.76311 -71.726298)
		(end 334.90281 -71.865998)
		(width 0.14732)
		(layer "In4.Cu")
		(net "CLK_100M_CK440_PCH_EXTCLK_DP")
	)
	(segment
		(start 337.16595 -71.865998)
		(end 337.53425 -71.865998)
		(width 0.14732)
		(layer "In4.Cu")
		(net "CLK_100M_CK440_PCH_EXTCLK_DP")
	)
	(segment
		(start 340.270592 -77.447394)
		(end 340.096094 -77.540358)
		(width 0.14732)
		(layer "In4.Cu")
		(net "CLK_100M_CK440_PCH_EXTCLK_DP")
	)
	(segment
		(start 339.988906 -77.89291)
		(end 340.08187 -78.067154)
		(width 0.14732)
		(layer "In4.Cu")
		(net "CLK_100M_CK440_PCH_EXTCLK_DP")
	)
	(segment
		(start 275.929852 -97.520252)
		(end 274.576032 -98.081084)
		(width 0.14732)
		(layer "In4.Cu")
		(net "CLK_100M_CK440_PCH_EXTCLK_DP")
	)
	(segment
		(start 333.282544 -72.376792)
		(end 332.987904 -72.082152)
		(width 0.14732)
		(layer "In4.Cu")
		(net "CLK_100M_CK440_PCH_EXTCLK_DP")
	)
	(segment
		(start 333.74711 -71.726298)
		(end 333.88681 -71.865998)
		(width 0.14732)
		(layer "In4.Cu")
		(net "CLK_100M_CK440_PCH_EXTCLK_DP")
	)
	(segment
		(start 338.296504 -83.129374)
		(end 338.29625 -83.129628)
		(width 0.14732)
		(layer "In4.Cu")
		(net "CLK_100M_CK440_PCH_EXTCLK_DP")
	)
	(segment
		(start 339.703156 -79.313532)
		(end 339.528658 -79.406496)
		(width 0.14732)
		(layer "In4.Cu")
		(net "CLK_100M_CK440_PCH_EXTCLK_DP")
	)
	(segment
		(start 274.576032 -98.081084)
		(end 265.016488 -107.640628)
		(width 0.14732)
		(layer "In4.Cu")
		(net "CLK_100M_CK440_PCH_EXTCLK_DP")
	)
	(segment
		(start 337.53425 -71.865998)
		(end 337.67395 -71.726298)
		(width 0.14732)
		(layer "In4.Cu")
		(net "CLK_100M_CK440_PCH_EXTCLK_DP")
	)
	(segment
		(start 340.096094 -77.540358)
		(end 339.988906 -77.89291)
		(width 0.14732)
		(layer "In4.Cu")
		(net "CLK_100M_CK440_PCH_EXTCLK_DP")
	)
	(segment
		(start 325.55815 -87.648796)
		(end 275.929852 -97.520252)
		(width 0.14732)
		(layer "In4.Cu")
		(net "CLK_100M_CK440_PCH_EXTCLK_DP")
	)
	(segment
		(start 257.561334 -108.65104)
		(end 257.561334 -109.658912)
		(width 0.14732)
		(layer "In4.Cu")
		(net "CLK_100M_CK440_PCH_EXTCLK_DP")
	)
	(segment
		(start 333.135224 -71.726298)
		(end 333.74711 -71.726298)
		(width 0.14732)
		(layer "In4.Cu")
		(net "CLK_100M_CK440_PCH_EXTCLK_DP")
	)
	(segment
		(start 332.987904 -71.873618)
		(end 333.135224 -71.726298)
		(width 0.14732)
		(layer "In4.Cu")
		(net "CLK_100M_CK440_PCH_EXTCLK_DP")
	)
	(segment
		(start 340.08187 -78.067154)
		(end 339.703156 -79.313532)
		(width 0.14732)
		(layer "In4.Cu")
		(net "CLK_100M_CK440_PCH_EXTCLK_DP")
	)
	(segment
		(start 265.016488 -107.640628)
		(end 258.571746 -107.640628)
		(width 0.14732)
		(layer "In4.Cu")
		(net "CLK_100M_CK440_PCH_EXTCLK_DP")
	)
	(segment
		(start 339.528658 -79.406496)
		(end 339.421724 -79.759048)
		(width 0.14732)
		(layer "In4.Cu")
		(net "CLK_100M_CK440_PCH_EXTCLK_DP")
	)
	(segment
		(start 336.42681 -71.726298)
		(end 337.02625 -71.726298)
		(width 0.14732)
		(layer "In4.Cu")
		(net "CLK_100M_CK440_PCH_EXTCLK_DP")
	)
	(segment
		(start 258.571746 -107.640628)
		(end 257.561334 -108.65104)
		(width 0.14732)
		(layer "In4.Cu")
		(net "CLK_100M_CK440_PCH_EXTCLK_DP")
	)
	(segment
		(start 328.09815 -85.951568)
		(end 325.55815 -87.648796)
		(width 0.14732)
		(layer "In4.Cu")
		(net "CLK_100M_CK440_PCH_EXTCLK_DP")
	)
	(segment
		(start 334.90281 -71.865998)
		(end 335.27111 -71.865998)
		(width 0.14732)
		(layer "In4.Cu")
		(net "CLK_100M_CK440_PCH_EXTCLK_DP")
	)
	(segment
		(start 258.192524 -108.554266)
		(end 257.84302 -108.90377)
		(width 0.13208)
		(layer "F.Cu")
		(net "CLK_100M_CK440_PCH_EXTCLK_DN")
	)
	(segment
		(start 257.84302 -108.90377)
		(end 257.84302 -109.666278)
		(width 0.13208)
		(layer "F.Cu")
		(net "CLK_100M_CK440_PCH_EXTCLK_DN")
	)
	(segment
		(start 336.09153 -58.703972)
		(end 336.399632 -58.39587)
		(width 0.0889)
		(layer "F.Cu")
		(net "CLK_100M_CK440_PCH_EXTCLK_DN")
	)
	(segment
		(start 257.84302 -109.666278)
		(end 258.130294 -109.953552)
		(width 0.13208)
		(layer "F.Cu")
		(net "CLK_100M_CK440_PCH_EXTCLK_DN")
	)
	(segment
		(start 336.09153 -59.012582)
		(end 336.09153 -58.703972)
		(width 0.0889)
		(layer "F.Cu")
		(net "CLK_100M_CK440_PCH_EXTCLK_DN")
	)
	(segment
		(start 332.738222 -67.335146)
		(end 332.738222 -67.32397)
		(width 0.0889)
		(layer "F.Cu")
		(net "CLK_100M_CK440_PCH_EXTCLK_DN")
	)
	(segment
		(start 336.399632 -58.39587)
		(end 336.399632 -58.020204)
		(width 0.0889)
		(layer "F.Cu")
		(net "CLK_100M_CK440_PCH_EXTCLK_DN")
	)
	(segment
		(start 332.772766 -65.930526)
		(end 335.044542 -63.65875)
		(width 0.0889)
		(layer "F.Cu")
		(net "CLK_100M_CK440_PCH_EXTCLK_DN")
	)
	(segment
		(start 332.772766 -67.289426)
		(end 332.772766 -65.930526)
		(width 0.0889)
		(layer "F.Cu")
		(net "CLK_100M_CK440_PCH_EXTCLK_DN")
	)
	(segment
		(start 332.418944 -72.376792)
		(end 332.738222 -72.057514)
		(width 0.13208)
		(layer "F.Cu")
		(net "CLK_100M_CK440_PCH_EXTCLK_DN")
	)
	(segment
		(start 336.209132 -59.130184)
		(end 336.09153 -59.012582)
		(width 0.0889)
		(layer "F.Cu")
		(net "CLK_100M_CK440_PCH_EXTCLK_DN")
	)
	(segment
		(start 332.738222 -67.32397)
		(end 332.772766 -67.289426)
		(width 0.0889)
		(layer "F.Cu")
		(net "CLK_100M_CK440_PCH_EXTCLK_DN")
	)
	(segment
		(start 335.044542 -63.65875)
		(end 335.044542 -61.600334)
		(width 0.0889)
		(layer "F.Cu")
		(net "CLK_100M_CK440_PCH_EXTCLK_DN")
	)
	(segment
		(start 336.209132 -60.435744)
		(end 336.209132 -59.130184)
		(width 0.0889)
		(layer "F.Cu")
		(net "CLK_100M_CK440_PCH_EXTCLK_DN")
	)
	(segment
		(start 332.738222 -72.057514)
		(end 332.738222 -67.335146)
		(width 0.13208)
		(layer "F.Cu")
		(net "CLK_100M_CK440_PCH_EXTCLK_DN")
	)
	(segment
		(start 335.044542 -61.600334)
		(end 336.209132 -60.435744)
		(width 0.0889)
		(layer "F.Cu")
		(net "CLK_100M_CK440_PCH_EXTCLK_DN")
	)
	(via
		(at 258.130294 -109.953552)
		(size 0.508)
		(drill 0.254)
		(layers "F.Cu" "B.Cu")
		(net "CLK_100M_CK440_PCH_EXTCLK_DN")
	)
	(via
		(at 332.418944 -72.376792)
		(size 0.508)
		(drill 0.254)
		(layers "F.Cu" "B.Cu")
		(net "CLK_100M_CK440_PCH_EXTCLK_DN")
	)
	(segment
		(start 340.427564 -72.08012)
		(end 341.4268 -73.079356)
		(width 0.14732)
		(layer "In4.Cu")
		(net "CLK_100M_CK440_PCH_EXTCLK_DN")
	)
	(segment
		(start 338.44865 -83.357974)
		(end 338.44865 -83.35772)
		(width 0.14732)
		(layer "In4.Cu")
		(net "CLK_100M_CK440_PCH_EXTCLK_DN")
	)
	(segment
		(start 328.205338 -86.21014)
		(end 325.665338 -87.907368)
		(width 0.14732)
		(layer "In4.Cu")
		(net "CLK_100M_CK440_PCH_EXTCLK_DN")
	)
	(segment
		(start 336.71256 -84.517992)
		(end 328.205338 -86.21014)
		(width 0.14732)
		(layer "In4.Cu")
		(net "CLK_100M_CK440_PCH_EXTCLK_DN")
	)
	(segment
		(start 325.665338 -87.907368)
		(end 276.009862 -97.784158)
		(width 0.14732)
		(layer "In4.Cu")
		(net "CLK_100M_CK440_PCH_EXTCLK_DN")
	)
	(segment
		(start 265.13028 -107.914948)
		(end 258.685538 -107.914948)
		(width 0.14732)
		(layer "In4.Cu")
		(net "CLK_100M_CK440_PCH_EXTCLK_DN")
	)
	(segment
		(start 338.448904 -83.35772)
		(end 338.44865 -83.357974)
		(width 0.14732)
		(layer "In4.Cu")
		(net "CLK_100M_CK440_PCH_EXTCLK_DN")
	)
	(segment
		(start 257.835654 -109.658912)
		(end 258.130294 -109.953552)
		(width 0.14732)
		(layer "In4.Cu")
		(net "CLK_100M_CK440_PCH_EXTCLK_DN")
	)
	(segment
		(start 341.4268 -73.079356)
		(end 341.4268 -74.136504)
		(width 0.14732)
		(layer "In4.Cu")
		(net "CLK_100M_CK440_PCH_EXTCLK_DN")
	)
	(segment
		(start 341.4268 -74.136504)
		(end 341.162894 -75.45578)
		(width 0.14732)
		(layer "In4.Cu")
		(net "CLK_100M_CK440_PCH_EXTCLK_DN")
	)
	(segment
		(start 339.477604 -80.99933)
		(end 338.518246 -83.311492)
		(width 0.14732)
		(layer "In4.Cu")
		(net "CLK_100M_CK440_PCH_EXTCLK_DN")
	)
	(segment
		(start 257.835654 -108.764832)
		(end 257.835654 -109.658912)
		(width 0.14732)
		(layer "In4.Cu")
		(net "CLK_100M_CK440_PCH_EXTCLK_DN")
	)
	(segment
		(start 258.685538 -107.914948)
		(end 257.835654 -108.764832)
		(width 0.14732)
		(layer "In4.Cu")
		(net "CLK_100M_CK440_PCH_EXTCLK_DN")
	)
	(segment
		(start 338.44865 -83.35772)
		(end 336.71256 -84.517992)
		(width 0.14732)
		(layer "In4.Cu")
		(net "CLK_100M_CK440_PCH_EXTCLK_DN")
	)
	(segment
		(start 332.418944 -72.376792)
		(end 332.713584 -72.082152)
		(width 0.14732)
		(layer "In4.Cu")
		(net "CLK_100M_CK440_PCH_EXTCLK_DN")
	)
	(segment
		(start 338.518246 -83.311492)
		(end 338.448904 -83.35772)
		(width 0.14732)
		(layer "In4.Cu")
		(net "CLK_100M_CK440_PCH_EXTCLK_DN")
	)
	(segment
		(start 274.73148 -98.313748)
		(end 265.13028 -107.914948)
		(width 0.14732)
		(layer "In4.Cu")
		(net "CLK_100M_CK440_PCH_EXTCLK_DN")
	)
	(segment
		(start 276.009862 -97.784158)
		(end 274.73148 -98.313748)
		(width 0.14732)
		(layer "In4.Cu")
		(net "CLK_100M_CK440_PCH_EXTCLK_DN")
	)
	(segment
		(start 332.713584 -71.759826)
		(end 333.021432 -71.451978)
		(width 0.14732)
		(layer "In4.Cu")
		(net "CLK_100M_CK440_PCH_EXTCLK_DN")
	)
	(segment
		(start 332.713584 -72.082152)
		(end 332.713584 -71.759826)
		(width 0.14732)
		(layer "In4.Cu")
		(net "CLK_100M_CK440_PCH_EXTCLK_DN")
	)
	(segment
		(start 341.162894 -75.45578)
		(end 339.477604 -80.99933)
		(width 0.14732)
		(layer "In4.Cu")
		(net "CLK_100M_CK440_PCH_EXTCLK_DN")
	)
	(segment
		(start 338.911184 -71.451978)
		(end 340.427564 -72.08012)
		(width 0.14732)
		(layer "In4.Cu")
		(net "CLK_100M_CK440_PCH_EXTCLK_DN")
	)
	(segment
		(start 333.021432 -71.451978)
		(end 338.911184 -71.451978)
		(width 0.14732)
		(layer "In4.Cu")
		(net "CLK_100M_CK440_PCH_EXTCLK_DN")
	)
	(segment
		(start 331.351382 -58.355992)
		(end 331.397102 -58.310272)
		(width 0.0889)
		(layer "F.Cu")
		(net "CLK_100M_BMC_P3E_DP")
	)
	(segment
		(start 325.79183 -64.076834)
		(end 326.119744 -64.404748)
		(width 0.0889)
		(layer "F.Cu")
		(net "CLK_100M_BMC_P3E_DP")
	)
	(segment
		(start 326.977248 -64.404748)
		(end 331.206602 -60.175394)
		(width 0.0889)
		(layer "F.Cu")
		(net "CLK_100M_BMC_P3E_DP")
	)
	(segment
		(start 331.089 -58.703972)
		(end 331.351382 -58.355992)
		(width 0.0889)
		(layer "F.Cu")
		(net "CLK_100M_BMC_P3E_DP")
	)
	(segment
		(start 331.206602 -60.175394)
		(end 331.206602 -59.100212)
		(width 0.0889)
		(layer "F.Cu")
		(net "CLK_100M_BMC_P3E_DP")
	)
	(segment
		(start 331.206602 -59.100212)
		(end 331.089 -58.98261)
		(width 0.0889)
		(layer "F.Cu")
		(net "CLK_100M_BMC_P3E_DP")
	)
	(segment
		(start 326.119744 -64.404748)
		(end 326.977248 -64.404748)
		(width 0.0889)
		(layer "F.Cu")
		(net "CLK_100M_BMC_P3E_DP")
	)
	(segment
		(start 331.089 -58.98261)
		(end 331.089 -58.703972)
		(width 0.0889)
		(layer "F.Cu")
		(net "CLK_100M_BMC_P3E_DP")
	)
	(segment
		(start 331.397102 -58.310272)
		(end 331.397102 -58.020204)
		(width 0.0889)
		(layer "F.Cu")
		(net "CLK_100M_BMC_P3E_DP")
	)
	(via
		(at 325.79183 -64.076834)
		(size 0.508)
		(drill 0.254)
		(layers "F.Cu" "B.Cu")
		(net "CLK_100M_BMC_P3E_DP")
	)
	(via
		(at 220.04782 -17.798288)
		(size 0.508)
		(drill 0.254)
		(layers "F.Cu" "B.Cu")
		(net "CLK_100M_BMC_P3E_DP")
	)
	(segment
		(start 170.83786 -14.540738)
		(end 170.83786 -15.149322)
		(width 0.13208)
		(layer "B.Cu")
		(net "CLK_100M_BMC_P3E_DP")
	)
	(segment
		(start 171.21632 -14.162278)
		(end 170.83786 -14.540738)
		(width 0.13208)
		(layer "B.Cu")
		(net "CLK_100M_BMC_P3E_DP")
	)
	(segment
		(start 219.74556 -17.496028)
		(end 220.04782 -17.798288)
		(width 0.13208)
		(layer "B.Cu")
		(net "CLK_100M_BMC_P3E_DP")
	)
	(segment
		(start 219.26423 -16.834612)
		(end 219.74556 -17.315942)
		(width 0.13208)
		(layer "B.Cu")
		(net "CLK_100M_BMC_P3E_DP")
	)
	(segment
		(start 193.265552 -16.937228)
		(end 193.98869 -16.638016)
		(width 0.13208)
		(layer "B.Cu")
		(net "CLK_100M_BMC_P3E_DP")
	)
	(segment
		(start 184.241948 -15.839948)
		(end 185.54192 -16.378428)
		(width 0.13208)
		(layer "B.Cu")
		(net "CLK_100M_BMC_P3E_DP")
	)
	(segment
		(start 171.175934 -15.487396)
		(end 172.027342 -15.839948)
		(width 0.13208)
		(layer "B.Cu")
		(net "CLK_100M_BMC_P3E_DP")
	)
	(segment
		(start 196.966078 -13.660628)
		(end 205.13675 -13.660628)
		(width 0.13208)
		(layer "B.Cu")
		(net "CLK_100M_BMC_P3E_DP")
	)
	(segment
		(start 193.98869 -16.638016)
		(end 196.966078 -13.660628)
		(width 0.13208)
		(layer "B.Cu")
		(net "CLK_100M_BMC_P3E_DP")
	)
	(segment
		(start 191.218566 -16.937228)
		(end 193.265552 -16.937228)
		(width 0.13208)
		(layer "B.Cu")
		(net "CLK_100M_BMC_P3E_DP")
	)
	(segment
		(start 205.13675 -13.660628)
		(end 217.574114 -16.134588)
		(width 0.13208)
		(layer "B.Cu")
		(net "CLK_100M_BMC_P3E_DP")
	)
	(segment
		(start 219.74556 -17.315942)
		(end 219.74556 -17.496028)
		(width 0.13208)
		(layer "B.Cu")
		(net "CLK_100M_BMC_P3E_DP")
	)
	(segment
		(start 185.54192 -16.378428)
		(end 191.218566 -16.937228)
		(width 0.13208)
		(layer "B.Cu")
		(net "CLK_100M_BMC_P3E_DP")
	)
	(segment
		(start 217.574114 -16.134588)
		(end 219.26423 -16.834612)
		(width 0.13208)
		(layer "B.Cu")
		(net "CLK_100M_BMC_P3E_DP")
	)
	(segment
		(start 172.027342 -15.839948)
		(end 184.241948 -15.839948)
		(width 0.13208)
		(layer "B.Cu")
		(net "CLK_100M_BMC_P3E_DP")
	)
	(segment
		(start 170.83786 -15.149322)
		(end 171.175934 -15.487396)
		(width 0.13208)
		(layer "B.Cu")
		(net "CLK_100M_BMC_P3E_DP")
	)
	(segment
		(start 329.60564 -76.688188)
		(end 328.178668 -78.11516)
		(width 0.14732)
		(layer "In4.Cu")
		(net "CLK_100M_BMC_P3E_DP")
	)
	(segment
		(start 227.296472 -59.5249)
		(end 224.36836 -52.455318)
		(width 0.14732)
		(layer "In4.Cu")
		(net "CLK_100M_BMC_P3E_DP")
	)
	(segment
		(start 330.13142 -75.41895)
		(end 329.60564 -76.688188)
		(width 0.14732)
		(layer "In4.Cu")
		(net "CLK_100M_BMC_P3E_DP")
	)
	(segment
		(start 219.75318 -17.181322)
		(end 219.75318 -17.503648)
		(width 0.14732)
		(layer "In4.Cu")
		(net "CLK_100M_BMC_P3E_DP")
	)
	(segment
		(start 328.178668 -78.11516)
		(end 322.572634 -80.437228)
		(width 0.14732)
		(layer "In4.Cu")
		(net "CLK_100M_BMC_P3E_DP")
	)
	(segment
		(start 219.75318 -17.503648)
		(end 220.04782 -17.798288)
		(width 0.14732)
		(layer "In4.Cu")
		(net "CLK_100M_BMC_P3E_DP")
	)
	(segment
		(start 329.335892 -68.912994)
		(end 330.13142 -72.912478)
		(width 0.14732)
		(layer "In4.Cu")
		(net "CLK_100M_BMC_P3E_DP")
	)
	(segment
		(start 224.36836 -45.764704)
		(end 220.034358 -35.301428)
		(width 0.14732)
		(layer "In4.Cu")
		(net "CLK_100M_BMC_P3E_DP")
	)
	(segment
		(start 302.922686 -84.454746)
		(end 265.41349 -84.454746)
		(width 0.14732)
		(layer "In4.Cu")
		(net "CLK_100M_BMC_P3E_DP")
	)
	(segment
		(start 218.33586 -16.873474)
		(end 219.445332 -16.873474)
		(width 0.14732)
		(layer "In4.Cu")
		(net "CLK_100M_BMC_P3E_DP")
	)
	(segment
		(start 234.056936 -66.285364)
		(end 227.296472 -59.5249)
		(width 0.14732)
		(layer "In4.Cu")
		(net "CLK_100M_BMC_P3E_DP")
	)
	(segment
		(start 217.7288 -17.480534)
		(end 218.33586 -16.873474)
		(width 0.14732)
		(layer "In4.Cu")
		(net "CLK_100M_BMC_P3E_DP")
	)
	(segment
		(start 217.7288 -23.7109)
		(end 217.7288 -17.480534)
		(width 0.14732)
		(layer "In4.Cu")
		(net "CLK_100M_BMC_P3E_DP")
	)
	(segment
		(start 219.445332 -16.873474)
		(end 219.75318 -17.181322)
		(width 0.14732)
		(layer "In4.Cu")
		(net "CLK_100M_BMC_P3E_DP")
	)
	(segment
		(start 220.034358 -35.301428)
		(end 217.7288 -23.7109)
		(width 0.14732)
		(layer "In4.Cu")
		(net "CLK_100M_BMC_P3E_DP")
	)
	(segment
		(start 265.41349 -84.454746)
		(end 255.714246 -80.437228)
		(width 0.14732)
		(layer "In4.Cu")
		(net "CLK_100M_BMC_P3E_DP")
	)
	(segment
		(start 330.13142 -72.912478)
		(end 330.13142 -75.41895)
		(width 0.14732)
		(layer "In4.Cu")
		(net "CLK_100M_BMC_P3E_DP")
	)
	(segment
		(start 327.735692 -65.049908)
		(end 329.335892 -68.912994)
		(width 0.14732)
		(layer "In4.Cu")
		(net "CLK_100M_BMC_P3E_DP")
	)
	(segment
		(start 326.08647 -64.371474)
		(end 327.057258 -64.371474)
		(width 0.14732)
		(layer "In4.Cu")
		(net "CLK_100M_BMC_P3E_DP")
	)
	(segment
		(start 253.725934 -80.437228)
		(end 247.365012 -77.802486)
		(width 0.14732)
		(layer "In4.Cu")
		(net "CLK_100M_BMC_P3E_DP")
	)
	(segment
		(start 255.714246 -80.437228)
		(end 253.725934 -80.437228)
		(width 0.14732)
		(layer "In4.Cu")
		(net "CLK_100M_BMC_P3E_DP")
	)
	(segment
		(start 224.36836 -52.455318)
		(end 224.36836 -45.764704)
		(width 0.14732)
		(layer "In4.Cu")
		(net "CLK_100M_BMC_P3E_DP")
	)
	(segment
		(start 325.79183 -64.076834)
		(end 326.08647 -64.371474)
		(width 0.14732)
		(layer "In4.Cu")
		(net "CLK_100M_BMC_P3E_DP")
	)
	(segment
		(start 312.62193 -80.437228)
		(end 302.922686 -84.454746)
		(width 0.14732)
		(layer "In4.Cu")
		(net "CLK_100M_BMC_P3E_DP")
	)
	(segment
		(start 239.455198 -69.892672)
		(end 234.056936 -66.285364)
		(width 0.14732)
		(layer "In4.Cu")
		(net "CLK_100M_BMC_P3E_DP")
	)
	(segment
		(start 247.365012 -77.802486)
		(end 239.455198 -69.892672)
		(width 0.14732)
		(layer "In4.Cu")
		(net "CLK_100M_BMC_P3E_DP")
	)
	(segment
		(start 327.057258 -64.371474)
		(end 327.735692 -65.049908)
		(width 0.14732)
		(layer "In4.Cu")
		(net "CLK_100M_BMC_P3E_DP")
	)
	(segment
		(start 322.572634 -80.437228)
		(end 312.62193 -80.437228)
		(width 0.14732)
		(layer "In4.Cu")
		(net "CLK_100M_BMC_P3E_DP")
	)
	(segment
		(start 327.056242 -64.594994)
		(end 327.78192 -63.869316)
		(width 0.0889)
		(layer "F.Cu")
		(net "CLK_100M_BMC_P3E_DN")
	)
	(segment
		(start 329.507088 -62.144148)
		(end 329.651106 -62.144148)
		(width 0.0889)
		(layer "F.Cu")
		(net "CLK_100M_BMC_P3E_DN")
	)
	(segment
		(start 330.944982 -60.850272)
		(end 331.088746 -60.706508)
		(width 0.0889)
		(layer "F.Cu")
		(net "CLK_100M_BMC_P3E_DN")
	)
	(segment
		(start 330.800964 -60.850272)
		(end 330.944982 -60.850272)
		(width 0.0889)
		(layer "F.Cu")
		(net "CLK_100M_BMC_P3E_DN")
	)
	(segment
		(start 329.651106 -62.144148)
		(end 329.79487 -62.00013)
		(width 0.0889)
		(layer "F.Cu")
		(net "CLK_100M_BMC_P3E_DN")
	)
	(segment
		(start 326.13727 -64.594994)
		(end 327.056242 -64.594994)
		(width 0.0889)
		(layer "F.Cu")
		(net "CLK_100M_BMC_P3E_DN")
	)
	(segment
		(start 331.396848 -59.100212)
		(end 331.397102 -59.099958)
		(width 0.0889)
		(layer "F.Cu")
		(net "CLK_100M_BMC_P3E_DN")
	)
	(segment
		(start 328.500994 -63.294006)
		(end 328.500994 -63.150242)
		(width 0.0889)
		(layer "F.Cu")
		(net "CLK_100M_BMC_P3E_DN")
	)
	(segment
		(start 330.657454 -61.137546)
		(end 330.657454 -60.993782)
		(width 0.0889)
		(layer "F.Cu")
		(net "CLK_100M_BMC_P3E_DN")
	)
	(segment
		(start 330.226162 -61.568838)
		(end 330.226162 -61.425074)
		(width 0.0889)
		(layer "F.Cu")
		(net "CLK_100M_BMC_P3E_DN")
	)
	(segment
		(start 330.51369 -61.281564)
		(end 330.657454 -61.137546)
		(width 0.0889)
		(layer "F.Cu")
		(net "CLK_100M_BMC_P3E_DN")
	)
	(segment
		(start 328.069702 -63.725298)
		(end 328.069702 -63.581534)
		(width 0.0889)
		(layer "F.Cu")
		(net "CLK_100M_BMC_P3E_DN")
	)
	(segment
		(start 327.78192 -63.869316)
		(end 327.925938 -63.869316)
		(width 0.0889)
		(layer "F.Cu")
		(net "CLK_100M_BMC_P3E_DN")
	)
	(segment
		(start 331.396848 -60.254388)
		(end 331.396848 -59.100212)
		(width 0.0889)
		(layer "F.Cu")
		(net "CLK_100M_BMC_P3E_DN")
	)
	(segment
		(start 325.79183 -64.940434)
		(end 326.13727 -64.594994)
		(width 0.0889)
		(layer "F.Cu")
		(net "CLK_100M_BMC_P3E_DN")
	)
	(segment
		(start 329.93838 -61.712856)
		(end 330.082398 -61.712856)
		(width 0.0889)
		(layer "F.Cu")
		(net "CLK_100M_BMC_P3E_DN")
	)
	(segment
		(start 329.075796 -62.57544)
		(end 329.219814 -62.57544)
		(width 0.0889)
		(layer "F.Cu")
		(net "CLK_100M_BMC_P3E_DN")
	)
	(segment
		(start 329.79487 -62.00013)
		(end 329.79487 -61.856366)
		(width 0.0889)
		(layer "F.Cu")
		(net "CLK_100M_BMC_P3E_DN")
	)
	(segment
		(start 330.082398 -61.712856)
		(end 330.226162 -61.568838)
		(width 0.0889)
		(layer "F.Cu")
		(net "CLK_100M_BMC_P3E_DN")
	)
	(segment
		(start 328.932286 -62.71895)
		(end 329.075796 -62.57544)
		(width 0.0889)
		(layer "F.Cu")
		(net "CLK_100M_BMC_P3E_DN")
	)
	(segment
		(start 329.219814 -62.57544)
		(end 329.363578 -62.431422)
		(width 0.0889)
		(layer "F.Cu")
		(net "CLK_100M_BMC_P3E_DN")
	)
	(segment
		(start 331.088746 -60.56249)
		(end 331.396848 -60.254388)
		(width 0.0889)
		(layer "F.Cu")
		(net "CLK_100M_BMC_P3E_DN")
	)
	(segment
		(start 328.500994 -63.150242)
		(end 328.644504 -63.006732)
		(width 0.0889)
		(layer "F.Cu")
		(net "CLK_100M_BMC_P3E_DN")
	)
	(segment
		(start 328.644504 -63.006732)
		(end 328.788522 -63.006732)
		(width 0.0889)
		(layer "F.Cu")
		(net "CLK_100M_BMC_P3E_DN")
	)
	(segment
		(start 329.79487 -61.856366)
		(end 329.93838 -61.712856)
		(width 0.0889)
		(layer "F.Cu")
		(net "CLK_100M_BMC_P3E_DN")
	)
	(segment
		(start 331.088746 -60.706508)
		(end 331.088746 -60.56249)
		(width 0.0889)
		(layer "F.Cu")
		(net "CLK_100M_BMC_P3E_DN")
	)
	(segment
		(start 329.363578 -62.431422)
		(end 329.363578 -62.287658)
		(width 0.0889)
		(layer "F.Cu")
		(net "CLK_100M_BMC_P3E_DN")
	)
	(segment
		(start 327.925938 -63.869316)
		(end 328.069702 -63.725298)
		(width 0.0889)
		(layer "F.Cu")
		(net "CLK_100M_BMC_P3E_DN")
	)
	(segment
		(start 328.932286 -62.862714)
		(end 328.932286 -62.71895)
		(width 0.0889)
		(layer "F.Cu")
		(net "CLK_100M_BMC_P3E_DN")
	)
	(segment
		(start 330.369672 -61.281564)
		(end 330.51369 -61.281564)
		(width 0.0889)
		(layer "F.Cu")
		(net "CLK_100M_BMC_P3E_DN")
	)
	(segment
		(start 331.397102 -59.099958)
		(end 331.397102 -58.850276)
		(width 0.0889)
		(layer "F.Cu")
		(net "CLK_100M_BMC_P3E_DN")
	)
	(segment
		(start 328.213212 -63.438024)
		(end 328.35723 -63.438024)
		(width 0.0889)
		(layer "F.Cu")
		(net "CLK_100M_BMC_P3E_DN")
	)
	(segment
		(start 330.226162 -61.425074)
		(end 330.369672 -61.281564)
		(width 0.0889)
		(layer "F.Cu")
		(net "CLK_100M_BMC_P3E_DN")
	)
	(segment
		(start 328.788522 -63.006732)
		(end 328.932286 -62.862714)
		(width 0.0889)
		(layer "F.Cu")
		(net "CLK_100M_BMC_P3E_DN")
	)
	(segment
		(start 329.363578 -62.287658)
		(end 329.507088 -62.144148)
		(width 0.0889)
		(layer "F.Cu")
		(net "CLK_100M_BMC_P3E_DN")
	)
	(segment
		(start 330.657454 -60.993782)
		(end 330.800964 -60.850272)
		(width 0.0889)
		(layer "F.Cu")
		(net "CLK_100M_BMC_P3E_DN")
	)
	(segment
		(start 328.069702 -63.581534)
		(end 328.213212 -63.438024)
		(width 0.0889)
		(layer "F.Cu")
		(net "CLK_100M_BMC_P3E_DN")
	)
	(segment
		(start 328.35723 -63.438024)
		(end 328.500994 -63.294006)
		(width 0.0889)
		(layer "F.Cu")
		(net "CLK_100M_BMC_P3E_DN")
	)
	(via
		(at 219.18422 -17.798288)
		(size 0.508)
		(drill 0.254)
		(layers "F.Cu" "B.Cu")
		(net "CLK_100M_BMC_P3E_DN")
	)
	(via
		(at 325.79183 -64.940434)
		(size 0.508)
		(drill 0.254)
		(layers "F.Cu" "B.Cu")
		(net "CLK_100M_BMC_P3E_DN")
	)
	(segment
		(start 217.498422 -16.383762)
		(end 219.117418 -17.054322)
		(width 0.13208)
		(layer "B.Cu")
		(net "CLK_100M_BMC_P3E_DN")
	)
	(segment
		(start 185.478166 -16.632682)
		(end 191.205612 -17.196308)
		(width 0.13208)
		(layer "B.Cu")
		(net "CLK_100M_BMC_P3E_DN")
	)
	(segment
		(start 171.029122 -15.707106)
		(end 171.97578 -16.099028)
		(width 0.13208)
		(layer "B.Cu")
		(net "CLK_100M_BMC_P3E_DN")
	)
	(segment
		(start 219.117418 -17.054322)
		(end 219.48648 -17.423384)
		(width 0.13208)
		(layer "B.Cu")
		(net "CLK_100M_BMC_P3E_DN")
	)
	(segment
		(start 171.97578 -16.099028)
		(end 184.190386 -16.099028)
		(width 0.13208)
		(layer "B.Cu")
		(net "CLK_100M_BMC_P3E_DN")
	)
	(segment
		(start 170.57878 -14.540738)
		(end 170.57878 -15.256764)
		(width 0.13208)
		(layer "B.Cu")
		(net "CLK_100M_BMC_P3E_DN")
	)
	(segment
		(start 191.205612 -17.196308)
		(end 193.317114 -17.196308)
		(width 0.13208)
		(layer "B.Cu")
		(net "CLK_100M_BMC_P3E_DN")
	)
	(segment
		(start 219.48648 -17.496028)
		(end 219.18422 -17.798288)
		(width 0.13208)
		(layer "B.Cu")
		(net "CLK_100M_BMC_P3E_DN")
	)
	(segment
		(start 193.317114 -17.196308)
		(end 194.135502 -16.857726)
		(width 0.13208)
		(layer "B.Cu")
		(net "CLK_100M_BMC_P3E_DN")
	)
	(segment
		(start 170.20032 -14.162278)
		(end 170.57878 -14.540738)
		(width 0.13208)
		(layer "B.Cu")
		(net "CLK_100M_BMC_P3E_DN")
	)
	(segment
		(start 219.48648 -17.423384)
		(end 219.48648 -17.496028)
		(width 0.13208)
		(layer "B.Cu")
		(net "CLK_100M_BMC_P3E_DN")
	)
	(segment
		(start 170.57878 -15.256764)
		(end 171.029122 -15.707106)
		(width 0.13208)
		(layer "B.Cu")
		(net "CLK_100M_BMC_P3E_DN")
	)
	(segment
		(start 194.135502 -16.857726)
		(end 197.07352 -13.919708)
		(width 0.13208)
		(layer "B.Cu")
		(net "CLK_100M_BMC_P3E_DN")
	)
	(segment
		(start 197.07352 -13.919708)
		(end 205.111096 -13.919708)
		(width 0.13208)
		(layer "B.Cu")
		(net "CLK_100M_BMC_P3E_DN")
	)
	(segment
		(start 184.190386 -16.099028)
		(end 185.478166 -16.632682)
		(width 0.13208)
		(layer "B.Cu")
		(net "CLK_100M_BMC_P3E_DN")
	)
	(segment
		(start 205.111096 -13.919708)
		(end 217.498422 -16.383762)
		(width 0.13208)
		(layer "B.Cu")
		(net "CLK_100M_BMC_P3E_DN")
	)
	(segment
		(start 218.400122 -25.678892)
		(end 218.50985 -25.514554)
		(width 0.14732)
		(layer "In4.Cu")
		(net "CLK_100M_BMC_P3E_DN")
	)
	(segment
		(start 219.47886 -17.503648)
		(end 219.18422 -17.798288)
		(width 0.14732)
		(layer "In4.Cu")
		(net "CLK_100M_BMC_P3E_DN")
	)
	(segment
		(start 266.85621 -84.180426)
		(end 266.71651 -84.040726)
		(width 0.14732)
		(layer "In4.Cu")
		(net "CLK_100M_BMC_P3E_DN")
	)
	(segment
		(start 265.4681 -84.180426)
		(end 255.768856 -80.162908)
		(width 0.14732)
		(layer "In4.Cu")
		(net "CLK_100M_BMC_P3E_DN")
	)
	(segment
		(start 219.23629 -29.881068)
		(end 219.346018 -29.71673)
		(width 0.14732)
		(layer "In4.Cu")
		(net "CLK_100M_BMC_P3E_DN")
	)
	(segment
		(start 224.64268 -45.710094)
		(end 220.298264 -35.221418)
		(width 0.14732)
		(layer "In4.Cu")
		(net "CLK_100M_BMC_P3E_DN")
	)
	(segment
		(start 218.311222 -24.51608)
		(end 218.23934 -24.154638)
		(width 0.14732)
		(layer "In4.Cu")
		(net "CLK_100M_BMC_P3E_DN")
	)
	(segment
		(start 312.56732 -80.162908)
		(end 302.868076 -84.180426)
		(width 0.14732)
		(layer "In4.Cu")
		(net "CLK_100M_BMC_P3E_DN")
	)
	(segment
		(start 218.00312 -19.379438)
		(end 218.00312 -19.011138)
		(width 0.14732)
		(layer "In4.Cu")
		(net "CLK_100M_BMC_P3E_DN")
	)
	(segment
		(start 329.10145 -69.857366)
		(end 329.173332 -70.218808)
		(width 0.14732)
		(layer "In4.Cu")
		(net "CLK_100M_BMC_P3E_DN")
	)
	(segment
		(start 218.847924 -27.21356)
		(end 218.683586 -27.103832)
		(width 0.14732)
		(layer "In4.Cu")
		(net "CLK_100M_BMC_P3E_DN")
	)
	(segment
		(start 224.64268 -52.400708)
		(end 224.64268 -45.710094)
		(width 0.14732)
		(layer "In4.Cu")
		(net "CLK_100M_BMC_P3E_DN")
	)
	(segment
		(start 247.52046 -77.569822)
		(end 239.630204 -69.679312)
		(width 0.14732)
		(layer "In4.Cu")
		(net "CLK_100M_BMC_P3E_DN")
	)
	(segment
		(start 266.34821 -84.040726)
		(end 266.20851 -84.180426)
		(width 0.14732)
		(layer "In4.Cu")
		(net "CLK_100M_BMC_P3E_DN")
	)
	(segment
		(start 268.74851 -84.040726)
		(end 268.38021 -84.040726)
		(width 0.14732)
		(layer "In4.Cu")
		(net "CLK_100M_BMC_P3E_DN")
	)
	(segment
		(start 329.8571 -73.387458)
		(end 329.7174 -73.527158)
		(width 0.14732)
		(layer "In4.Cu")
		(net "CLK_100M_BMC_P3E_DN")
	)
	(segment
		(start 218.919806 -27.575002)
		(end 218.847924 -27.21356)
		(width 0.14732)
		(layer "In4.Cu")
		(net "CLK_100M_BMC_P3E_DN")
	)
	(segment
		(start 253.780544 -80.162908)
		(end 247.52046 -77.569822)
		(width 0.14732)
		(layer "In4.Cu")
		(net "CLK_100M_BMC_P3E_DN")
	)
	(segment
		(start 329.372976 -76.53274)
		(end 328.02322 -77.882496)
		(width 0.14732)
		(layer "In4.Cu")
		(net "CLK_100M_BMC_P3E_DN")
	)
	(segment
		(start 219.33154 -17.147794)
		(end 219.47886 -17.295114)
		(width 0.14732)
		(layer "In4.Cu")
		(net "CLK_100M_BMC_P3E_DN")
	)
	(segment
		(start 218.00312 -23.683722)
		(end 218.00312 -22.081998)
		(width 0.14732)
		(layer "In4.Cu")
		(net "CLK_100M_BMC_P3E_DN")
	)
	(segment
		(start 327.961752 -66.677794)
		(end 328.102722 -67.018154)
		(width 0.14732)
		(layer "In4.Cu")
		(net "CLK_100M_BMC_P3E_DN")
	)
	(segment
		(start 267.87221 -84.180426)
		(end 267.73251 -84.040726)
		(width 0.14732)
		(layer "In4.Cu")
		(net "CLK_100M_BMC_P3E_DN")
	)
	(segment
		(start 267.73251 -84.040726)
		(end 267.36421 -84.040726)
		(width 0.14732)
		(layer "In4.Cu")
		(net "CLK_100M_BMC_P3E_DN")
	)
	(segment
		(start 218.14282 -19.887438)
		(end 218.14282 -19.519138)
		(width 0.14732)
		(layer "In4.Cu")
		(net "CLK_100M_BMC_P3E_DN")
	)
	(segment
		(start 327.713848 -66.07937)
		(end 327.896474 -66.155062)
		(width 0.14732)
		(layer "In4.Cu")
		(net "CLK_100M_BMC_P3E_DN")
	)
	(segment
		(start 218.00312 -21.043138)
		(end 218.14282 -20.903438)
		(width 0.14732)
		(layer "In4.Cu")
		(net "CLK_100M_BMC_P3E_DN")
	)
	(segment
		(start 328.285348 -67.093846)
		(end 328.42962 -67.44208)
		(width 0.14732)
		(layer "In4.Cu")
		(net "CLK_100M_BMC_P3E_DN")
	)
	(segment
		(start 328.02322 -77.882496)
		(end 322.518024 -80.162908)
		(width 0.14732)
		(layer "In4.Cu")
		(net "CLK_100M_BMC_P3E_DN")
	)
	(segment
		(start 218.14282 -20.903438)
		(end 218.14282 -20.535138)
		(width 0.14732)
		(layer "In4.Cu")
		(net "CLK_100M_BMC_P3E_DN")
	)
	(segment
		(start 219.147644 -28.720034)
		(end 219.075762 -28.358592)
		(width 0.14732)
		(layer "In4.Cu")
		(net "CLK_100M_BMC_P3E_DN")
	)
	(segment
		(start 329.33767 -70.328536)
		(end 329.54849 -71.388224)
		(width 0.14732)
		(layer "In4.Cu")
		(net "CLK_100M_BMC_P3E_DN")
	)
	(segment
		(start 329.173332 -70.218808)
		(end 329.33767 -70.328536)
		(width 0.14732)
		(layer "In4.Cu")
		(net "CLK_100M_BMC_P3E_DN")
	)
	(segment
		(start 328.353928 -67.624706)
		(end 328.494898 -67.965066)
		(width 0.14732)
		(layer "In4.Cu")
		(net "CLK_100M_BMC_P3E_DN")
	)
	(segment
		(start 218.911424 -28.248864)
		(end 218.810078 -27.73934)
		(width 0.14732)
		(layer "In4.Cu")
		(net "CLK_100M_BMC_P3E_DN")
	)
	(segment
		(start 329.438508 -71.552562)
		(end 329.51039 -71.914004)
		(width 0.14732)
		(layer "In4.Cu")
		(net "CLK_100M_BMC_P3E_DN")
	)
	(segment
		(start 329.7174 -73.895458)
		(end 329.8571 -74.035158)
		(width 0.14732)
		(layer "In4.Cu")
		(net "CLK_100M_BMC_P3E_DN")
	)
	(segment
		(start 329.674982 -72.023732)
		(end 329.8571 -72.939656)
		(width 0.14732)
		(layer "In4.Cu")
		(net "CLK_100M_BMC_P3E_DN")
	)
	(segment
		(start 219.274136 -29.355288)
		(end 219.109544 -29.24556)
		(width 0.14732)
		(layer "In4.Cu")
		(net "CLK_100M_BMC_P3E_DN")
	)
	(segment
		(start 218.23934 -24.154638)
		(end 218.074748 -24.04491)
		(width 0.14732)
		(layer "In4.Cu")
		(net "CLK_100M_BMC_P3E_DN")
	)
	(segment
		(start 322.518024 -80.162908)
		(end 312.56732 -80.162908)
		(width 0.14732)
		(layer "In4.Cu")
		(net "CLK_100M_BMC_P3E_DN")
	)
	(segment
		(start 268.38021 -84.040726)
		(end 268.24051 -84.180426)
		(width 0.14732)
		(layer "In4.Cu")
		(net "CLK_100M_BMC_P3E_DN")
	)
	(segment
		(start 218.27363 -25.043384)
		(end 218.201494 -24.680418)
		(width 0.14732)
		(layer "In4.Cu")
		(net "CLK_100M_BMC_P3E_DN")
	)
	(segment
		(start 239.630204 -69.679312)
		(end 234.231942 -66.072004)
		(width 0.14732)
		(layer "In4.Cu")
		(net "CLK_100M_BMC_P3E_DN")
	)
	(segment
		(start 327.896474 -66.155062)
		(end 328.03719 -66.495168)
		(width 0.14732)
		(layer "In4.Cu")
		(net "CLK_100M_BMC_P3E_DN")
	)
	(segment
		(start 267.36421 -84.040726)
		(end 267.22451 -84.180426)
		(width 0.14732)
		(layer "In4.Cu")
		(net "CLK_100M_BMC_P3E_DN")
	)
	(segment
		(start 266.20851 -84.180426)
		(end 265.4681 -84.180426)
		(width 0.14732)
		(layer "In4.Cu")
		(net "CLK_100M_BMC_P3E_DN")
	)
	(segment
		(start 218.14282 -18.503138)
		(end 218.00312 -18.363438)
		(width 0.14732)
		(layer "In4.Cu")
		(net "CLK_100M_BMC_P3E_DN")
	)
	(segment
		(start 255.768856 -80.162908)
		(end 253.780544 -80.162908)
		(width 0.14732)
		(layer "In4.Cu")
		(net "CLK_100M_BMC_P3E_DN")
	)
	(segment
		(start 329.54849 -71.388224)
		(end 329.438508 -71.552562)
		(width 0.14732)
		(layer "In4.Cu")
		(net "CLK_100M_BMC_P3E_DN")
	)
	(segment
		(start 218.438222 -25.153112)
		(end 218.27363 -25.043384)
		(width 0.14732)
		(layer "In4.Cu")
		(net "CLK_100M_BMC_P3E_DN")
	)
	(segment
		(start 220.298264 -35.221418)
		(end 219.434664 -30.877764)
		(width 0.14732)
		(layer "In4.Cu")
		(net "CLK_100M_BMC_P3E_DN")
	)
	(segment
		(start 329.51039 -71.914004)
		(end 329.674982 -72.023732)
		(width 0.14732)
		(layer "In4.Cu")
		(net "CLK_100M_BMC_P3E_DN")
	)
	(segment
		(start 327.503028 -65.205356)
		(end 327.648316 -65.556384)
		(width 0.14732)
		(layer "In4.Cu")
		(net "CLK_100M_BMC_P3E_DN")
	)
	(segment
		(start 219.47886 -17.295114)
		(end 219.47886 -17.503648)
		(width 0.14732)
		(layer "In4.Cu")
		(net "CLK_100M_BMC_P3E_DN")
	)
	(segment
		(start 328.102722 -67.018154)
		(end 328.285348 -67.093846)
		(width 0.14732)
		(layer "In4.Cu")
		(net "CLK_100M_BMC_P3E_DN")
	)
	(segment
		(start 329.071986 -68.993004)
		(end 329.211178 -69.693028)
		(width 0.14732)
		(layer "In4.Cu")
		(net "CLK_100M_BMC_P3E_DN")
	)
	(segment
		(start 218.14282 -21.942298)
		(end 218.14282 -21.573998)
		(width 0.14732)
		(layer "In4.Cu")
		(net "CLK_100M_BMC_P3E_DN")
	)
	(segment
		(start 218.00312 -22.081998)
		(end 218.14282 -21.942298)
		(width 0.14732)
		(layer "In4.Cu")
		(net "CLK_100M_BMC_P3E_DN")
	)
	(segment
		(start 219.434664 -30.877764)
		(end 219.544392 -30.713426)
		(width 0.14732)
		(layer "In4.Cu")
		(net "CLK_100M_BMC_P3E_DN")
	)
	(segment
		(start 218.810078 -27.73934)
		(end 218.919806 -27.575002)
		(width 0.14732)
		(layer "In4.Cu")
		(net "CLK_100M_BMC_P3E_DN")
	)
	(segment
		(start 329.8571 -75.36434)
		(end 329.372976 -76.53274)
		(width 0.14732)
		(layer "In4.Cu")
		(net "CLK_100M_BMC_P3E_DN")
	)
	(segment
		(start 219.075762 -28.358592)
		(end 218.911424 -28.248864)
		(width 0.14732)
		(layer "In4.Cu")
		(net "CLK_100M_BMC_P3E_DN")
	)
	(segment
		(start 227.529136 -59.369452)
		(end 224.64268 -52.400708)
		(width 0.14732)
		(layer "In4.Cu")
		(net "CLK_100M_BMC_P3E_DN")
	)
	(segment
		(start 218.14282 -20.535138)
		(end 218.00312 -20.395438)
		(width 0.14732)
		(layer "In4.Cu")
		(net "CLK_100M_BMC_P3E_DN")
	)
	(segment
		(start 328.42962 -67.44208)
		(end 328.353928 -67.624706)
		(width 0.14732)
		(layer "In4.Cu")
		(net "CLK_100M_BMC_P3E_DN")
	)
	(segment
		(start 218.14282 -19.519138)
		(end 218.00312 -19.379438)
		(width 0.14732)
		(layer "In4.Cu")
		(net "CLK_100M_BMC_P3E_DN")
	)
	(segment
		(start 329.211178 -69.693028)
		(end 329.10145 -69.857366)
		(width 0.14732)
		(layer "In4.Cu")
		(net "CLK_100M_BMC_P3E_DN")
	)
	(segment
		(start 218.683586 -27.103832)
		(end 218.400122 -25.678892)
		(width 0.14732)
		(layer "In4.Cu")
		(net "CLK_100M_BMC_P3E_DN")
	)
	(segment
		(start 268.24051 -84.180426)
		(end 267.87221 -84.180426)
		(width 0.14732)
		(layer "In4.Cu")
		(net "CLK_100M_BMC_P3E_DN")
	)
	(segment
		(start 326.943466 -64.645794)
		(end 327.503028 -65.205356)
		(width 0.14732)
		(layer "In4.Cu")
		(net "CLK_100M_BMC_P3E_DN")
	)
	(segment
		(start 327.648316 -65.556384)
		(end 327.572878 -65.73901)
		(width 0.14732)
		(layer "In4.Cu")
		(net "CLK_100M_BMC_P3E_DN")
	)
	(segment
		(start 219.307918 -30.242256)
		(end 219.23629 -29.881068)
		(width 0.14732)
		(layer "In4.Cu")
		(net "CLK_100M_BMC_P3E_DN")
	)
	(segment
		(start 326.08647 -64.645794)
		(end 326.943466 -64.645794)
		(width 0.14732)
		(layer "In4.Cu")
		(net "CLK_100M_BMC_P3E_DN")
	)
	(segment
		(start 267.22451 -84.180426)
		(end 266.85621 -84.180426)
		(width 0.14732)
		(layer "In4.Cu")
		(net "CLK_100M_BMC_P3E_DN")
	)
	(segment
		(start 327.572878 -65.73901)
		(end 327.713848 -66.07937)
		(width 0.14732)
		(layer "In4.Cu")
		(net "CLK_100M_BMC_P3E_DN")
	)
	(segment
		(start 328.494898 -67.965066)
		(end 328.677524 -68.040758)
		(width 0.14732)
		(layer "In4.Cu")
		(net "CLK_100M_BMC_P3E_DN")
	)
	(segment
		(start 329.7174 -73.527158)
		(end 329.7174 -73.895458)
		(width 0.14732)
		(layer "In4.Cu")
		(net "CLK_100M_BMC_P3E_DN")
	)
	(segment
		(start 328.03719 -66.495168)
		(end 327.961752 -66.677794)
		(width 0.14732)
		(layer "In4.Cu")
		(net "CLK_100M_BMC_P3E_DN")
	)
	(segment
		(start 218.00312 -18.363438)
		(end 218.00312 -17.594326)
		(width 0.14732)
		(layer "In4.Cu")
		(net "CLK_100M_BMC_P3E_DN")
	)
	(segment
		(start 219.47251 -30.351984)
		(end 219.307918 -30.242256)
		(width 0.14732)
		(layer "In4.Cu")
		(net "CLK_100M_BMC_P3E_DN")
	)
	(segment
		(start 268.88821 -84.180426)
		(end 268.74851 -84.040726)
		(width 0.14732)
		(layer "In4.Cu")
		(net "CLK_100M_BMC_P3E_DN")
	)
	(segment
		(start 329.8571 -72.939656)
		(end 329.8571 -73.387458)
		(width 0.14732)
		(layer "In4.Cu")
		(net "CLK_100M_BMC_P3E_DN")
	)
	(segment
		(start 218.449652 -17.147794)
		(end 219.33154 -17.147794)
		(width 0.14732)
		(layer "In4.Cu")
		(net "CLK_100M_BMC_P3E_DN")
	)
	(segment
		(start 234.231942 -66.072004)
		(end 227.529136 -59.369452)
		(width 0.14732)
		(layer "In4.Cu")
		(net "CLK_100M_BMC_P3E_DN")
	)
	(segment
		(start 219.037916 -28.884372)
		(end 219.147644 -28.720034)
		(width 0.14732)
		(layer "In4.Cu")
		(net "CLK_100M_BMC_P3E_DN")
	)
	(segment
		(start 218.074748 -24.04491)
		(end 218.00312 -23.683722)
		(width 0.14732)
		(layer "In4.Cu")
		(net "CLK_100M_BMC_P3E_DN")
	)
	(segment
		(start 329.8571 -74.035158)
		(end 329.8571 -75.36434)
		(width 0.14732)
		(layer "In4.Cu")
		(net "CLK_100M_BMC_P3E_DN")
	)
	(segment
		(start 219.109544 -29.24556)
		(end 219.037916 -28.884372)
		(width 0.14732)
		(layer "In4.Cu")
		(net "CLK_100M_BMC_P3E_DN")
	)
	(segment
		(start 218.00312 -19.011138)
		(end 218.14282 -18.871438)
		(width 0.14732)
		(layer "In4.Cu")
		(net "CLK_100M_BMC_P3E_DN")
	)
	(segment
		(start 219.346018 -29.71673)
		(end 219.274136 -29.355288)
		(width 0.14732)
		(layer "In4.Cu")
		(net "CLK_100M_BMC_P3E_DN")
	)
	(segment
		(start 218.00312 -17.594326)
		(end 218.449652 -17.147794)
		(width 0.14732)
		(layer "In4.Cu")
		(net "CLK_100M_BMC_P3E_DN")
	)
	(segment
		(start 218.00312 -20.395438)
		(end 218.00312 -20.027138)
		(width 0.14732)
		(layer "In4.Cu")
		(net "CLK_100M_BMC_P3E_DN")
	)
	(segment
		(start 325.79183 -64.940434)
		(end 326.08647 -64.645794)
		(width 0.14732)
		(layer "In4.Cu")
		(net "CLK_100M_BMC_P3E_DN")
	)
	(segment
		(start 218.14282 -18.871438)
		(end 218.14282 -18.503138)
		(width 0.14732)
		(layer "In4.Cu")
		(net "CLK_100M_BMC_P3E_DN")
	)
	(segment
		(start 218.50985 -25.514554)
		(end 218.438222 -25.153112)
		(width 0.14732)
		(layer "In4.Cu")
		(net "CLK_100M_BMC_P3E_DN")
	)
	(segment
		(start 219.544392 -30.713426)
		(end 219.47251 -30.351984)
		(width 0.14732)
		(layer "In4.Cu")
		(net "CLK_100M_BMC_P3E_DN")
	)
	(segment
		(start 302.868076 -84.180426)
		(end 268.88821 -84.180426)
		(width 0.14732)
		(layer "In4.Cu")
		(net "CLK_100M_BMC_P3E_DN")
	)
	(segment
		(start 218.00312 -20.027138)
		(end 218.14282 -19.887438)
		(width 0.14732)
		(layer "In4.Cu")
		(net "CLK_100M_BMC_P3E_DN")
	)
	(segment
		(start 328.677524 -68.040758)
		(end 329.071986 -68.993004)
		(width 0.14732)
		(layer "In4.Cu")
		(net "CLK_100M_BMC_P3E_DN")
	)
	(segment
		(start 218.201494 -24.680418)
		(end 218.311222 -24.51608)
		(width 0.14732)
		(layer "In4.Cu")
		(net "CLK_100M_BMC_P3E_DN")
	)
	(segment
		(start 218.00312 -21.434298)
		(end 218.00312 -21.043138)
		(width 0.14732)
		(layer "In4.Cu")
		(net "CLK_100M_BMC_P3E_DN")
	)
	(segment
		(start 218.14282 -21.573998)
		(end 218.00312 -21.434298)
		(width 0.14732)
		(layer "In4.Cu")
		(net "CLK_100M_BMC_P3E_DN")
	)
	(segment
		(start 266.71651 -84.040726)
		(end 266.34821 -84.040726)
		(width 0.14732)
		(layer "In4.Cu")
		(net "CLK_100M_BMC_P3E_DN")
	)
	(zone
		(layer "F.Cu")
		(hatch none 0.5)
		(connect_pads
			(clearance 0)
		)
		(min_thickness 0.25)
		(keepout
			(tracks allowed)
			(vias allowed)
			(pads allowed)
			(copperpour allowed)
			(footprints allowed)
		)
		(placement
			(enabled no)
			(sheetname "")
		)
		(fill
			(thermal_gap 0.5)
			(thermal_bridge_width 0.5)
			(island_removal_mode 0)
		)
		(polygon
			(pts
				(xy 62.147958 -274.466558) (xy 59.822842 -274.466558) (xy 59.491118 -274.466558) (xy 59.491118 -273.216116)
				(xy 62.40653 -273.216116) (xy 62.40653 -274.466558)
			)
		)
	)
	(zone
		(layer "F.Cu")
		(hatch none 0.5)
		(connect_pads
			(clearance 0)
		)
		(min_thickness 0.25)
		(keepout
			(tracks allowed)
			(vias allowed)
			(pads allowed)
			(copperpour allowed)
			(footprints allowed)
		)
		(placement
			(enabled no)
			(sheetname "")
		)
		(fill
			(thermal_gap 0.5)
			(thermal_bridge_width 0.5)
			(island_removal_mode 0)
		)
		(polygon
			(pts
				(xy 292.67531 -273.61642) (xy 292.67531 -273.172682) (xy 295.000426 -273.172682) (xy 295.000426 -273.61642)
			)
		)
	)
	(zone
		(layer "F.Cu")
		(hatch none 0.5)
		(connect_pads
			(clearance 0)
		)
		(min_thickness 0.25)
		(keepout
			(tracks allowed)
			(vias allowed)
			(pads allowed)
			(copperpour allowed)
			(footprints not_allowed)
		)
		(placement
			(enabled no)
			(sheetname "")
		)
		(fill
			(thermal_gap 0.5)
			(thermal_bridge_width 0.5)
			(island_removal_mode 0)
		)
		(polygon
			(pts
				(xy 464.59394 -182.236872) (xy 474.59392 -182.236872) (xy 474.59392 -166.236904) (xy 464.59394 -166.236904)
			)
		)
	)
	(zone
		(layer "F.Cu")
		(hatch none 0.5)
		(connect_pads
			(clearance 0)
		)
		(min_thickness 0.25)
		(keepout
			(tracks allowed)
			(vias allowed)
			(pads allowed)
			(copperpour allowed)
			(footprints allowed)
		)
		(placement
			(enabled no)
			(sheetname "")
		)
		(fill
			(thermal_gap 0.5)
			(thermal_bridge_width 0.5)
			(island_removal_mode 0)
		)
		(polygon
			(pts
				(xy 14.560042 -267.66647) (xy 14.560042 -267.222732) (xy 16.885158 -267.222732) (xy 16.885158 -267.66647)
			)
		)
	)
	(zone
		(layer "F.Cu")
		(hatch none 0.5)
		(connect_pads
			(clearance 0)
		)
		(min_thickness 0.25)
		(keepout
			(tracks allowed)
			(vias allowed)
			(pads allowed)
			(copperpour allowed)
			(footprints allowed)
		)
		(placement
			(enabled no)
			(sheetname "")
		)
		(fill
			(thermal_gap 0.5)
			(thermal_bridge_width 0.5)
			(island_removal_mode 0)
		)
		(polygon
			(pts
				(xy 405.43226 -5.888228) (xy 405.43226 -3.952748) (xy 407.60396 -3.952748) (xy 407.60396 -5.888228)
			)
		)
	)
	(zone
		(layer "F.Cu")
		(hatch none 0.5)
		(connect_pads
			(clearance 0)
		)
		(min_thickness 0.25)
		(keepout
			(tracks allowed)
			(vias allowed)
			(pads allowed)
			(copperpour allowed)
			(footprints allowed)
		)
		(placement
			(enabled no)
			(sheetname "")
		)
		(fill
			(thermal_gap 0.5)
			(thermal_bridge_width 0.5)
			(island_removal_mode 0)
		)
		(polygon
			(pts
				(xy 423.643806 -351.202752) (xy 423.643806 -348.348808) (xy 428.015146 -348.348808) (xy 428.015146 -351.202752)
			)
		)
	)
	(zone
		(layer "F.Cu")
		(hatch none 0.5)
		(connect_pads
			(clearance 0)
		)
		(min_thickness 0.25)
		(keepout
			(tracks allowed)
			(vias allowed)
			(pads allowed)
			(copperpour allowed)
			(footprints allowed)
		)
		(placement
			(enabled no)
			(sheetname "")
		)
		(fill
			(thermal_gap 0.5)
			(thermal_bridge_width 0.5)
			(island_removal_mode 0)
		)
		(polygon
			(pts
				(xy 309.649622 -404.802594) (xy 309.649622 -399.959576) (xy 311.534048 -399.959576) (xy 311.534048 -404.802594)
			)
		)
	)
	(zone
		(layer "F.Cu")
		(hatch none 0.5)
		(connect_pads
			(clearance 0)
		)
		(min_thickness 0.25)
		(keepout
			(tracks allowed)
			(vias allowed)
			(pads allowed)
			(copperpour allowed)
			(footprints allowed)
		)
		(placement
			(enabled no)
			(sheetname "")
		)
		(fill
			(thermal_gap 0.5)
			(thermal_bridge_width 0.5)
			(island_removal_mode 0)
		)
		(polygon
			(pts
				(xy 63.977012 -222.616522) (xy 63.977012 -222.172784) (xy 66.186812 -222.172784) (xy 66.186812 -222.616522)
			)
		)
	)
	(zone
		(layer "F.Cu")
		(hatch none 0.5)
		(connect_pads
			(clearance 0)
		)
		(min_thickness 0.25)
		(keepout
			(tracks allowed)
			(vias allowed)
			(pads allowed)
			(copperpour allowed)
			(footprints allowed)
		)
		(placement
			(enabled no)
			(sheetname "")
		)
		(fill
			(thermal_gap 0.5)
			(thermal_bridge_width 0.5)
			(island_removal_mode 0)
		)
		(polygon
			(pts
				(xy 185.21426 -404.39086) (xy 185.21426 -401.01774) (xy 188.595 -401.01774) (xy 188.595 -404.39086)
			)
		)
	)
	(zone
		(layer "F.Cu")
		(hatch none 0.5)
		(connect_pads
			(clearance 0)
		)
		(min_thickness 0.25)
		(keepout
			(tracks allowed)
			(vias allowed)
			(pads allowed)
			(copperpour allowed)
			(footprints allowed)
		)
		(placement
			(enabled no)
			(sheetname "")
		)
		(fill
			(thermal_gap 0.5)
			(thermal_bridge_width 0.5)
			(island_removal_mode 0)
		)
		(polygon
			(pts
				(xy 277.58771 -196.266562) (xy 277.58771 -195.822824) (xy 279.912826 -195.822824) (xy 279.912826 -196.266562)
			)
		)
	)
	(zone
		(layer "F.Cu")
		(hatch none 0.5)
		(connect_pads
			(clearance 0)
		)
		(min_thickness 0.25)
		(keepout
			(tracks allowed)
			(vias allowed)
			(pads allowed)
			(copperpour allowed)
			(footprints allowed)
		)
		(placement
			(enabled no)
			(sheetname "")
		)
		(fill
			(thermal_gap 0.5)
			(thermal_bridge_width 0.5)
			(island_removal_mode 0)
		)
		(polygon
			(pts
				(xy 413.275526 -295.604946) (xy 413.275526 -295.376346) (xy 415.307526 -295.376346) (xy 415.307526 -295.604946)
			)
		)
	)
	(zone
		(layer "F.Cu")
		(hatch none 0.5)
		(connect_pads
			(clearance 0)
		)
		(min_thickness 0.25)
		(keepout
			(tracks allowed)
			(vias allowed)
			(pads allowed)
			(copperpour allowed)
			(footprints allowed)
		)
		(placement
			(enabled no)
			(sheetname "")
		)
		(fill
			(thermal_gap 0.5)
			(thermal_bridge_width 0.5)
			(island_removal_mode 0)
		)
		(polygon
			(pts
				(xy 210.598258 -282.854908) (xy 210.598258 -282.626308) (xy 212.630258 -282.626308) (xy 212.630258 -282.854908)
			)
		)
	)
	(zone
		(layer "F.Cu")
		(hatch none 0.5)
		(connect_pads
			(clearance 0)
		)
		(min_thickness 0.25)
		(keepout
			(tracks allowed)
			(vias allowed)
			(pads allowed)
			(copperpour allowed)
			(footprints allowed)
		)
		(placement
			(enabled no)
			(sheetname "")
		)
		(fill
			(thermal_gap 0.5)
			(thermal_bridge_width 0.5)
			(island_removal_mode 0)
		)
		(polygon
			(pts
				(xy 207.154526 -275.82622) (xy 209.186526 -275.82622) (xy 209.186526 -276.05482) (xy 207.154526 -276.05482)
				(xy 207.023208 -276.05482) (xy 206.9973 -276.05482) (xy 206.9973 -275.82622) (xy 207.023208 -275.82622)
			)
		)
	)
	(zone
		(layer "F.Cu")
		(hatch none 0.5)
		(connect_pads
			(clearance 0)
		)
		(min_thickness 0.25)
		(keepout
			(tracks allowed)
			(vias allowed)
			(pads allowed)
			(copperpour allowed)
			(footprints allowed)
		)
		(placement
			(enabled no)
			(sheetname "")
		)
		(fill
			(thermal_gap 0.5)
			(thermal_bridge_width 0.5)
			(island_removal_mode 0)
		)
		(polygon
			(pts
				(xy 192.066926 -246.304816) (xy 192.066926 -246.076216) (xy 194.098926 -246.076216) (xy 194.098926 -246.304816)
			)
		)
	)
	(zone
		(layer "F.Cu")
		(hatch none 0.5)
		(connect_pads
			(clearance 0)
		)
		(min_thickness 0.25)
		(keepout
			(tracks allowed)
			(vias allowed)
			(pads allowed)
			(copperpour allowed)
			(footprints allowed)
		)
		(placement
			(enabled no)
			(sheetname "")
		)
		(fill
			(thermal_gap 0.5)
			(thermal_bridge_width 0.5)
			(island_removal_mode 0)
		)
		(polygon
			(pts
				(xy 99.636072 -333.586582) (xy 96.100392 -333.586582) (xy 96.100392 -331.503782) (xy 99.636072 -331.503782)
			)
		)
	)
	(zone
		(layer "F.Cu")
		(hatch none 0.5)
		(connect_pads
			(clearance 0)
		)
		(min_thickness 0.25)
		(keepout
			(tracks allowed)
			(vias allowed)
			(pads allowed)
			(copperpour allowed)
			(footprints not_allowed)
		)
		(placement
			(enabled no)
			(sheetname "")
		)
		(fill
			(thermal_gap 0.5)
			(thermal_bridge_width 0.5)
			(island_removal_mode 0)
		)
		(polygon
			(pts
				(arc
					(start 227.65004 -44.500038)
					(mid 228.650038 -43.50004)
					(end 229.650036 -44.500038)
				)
				(arc
					(start 229.650036 -44.500038)
					(mid 228.650038 -45.500036)
					(end 227.65004 -44.500038)
				)
			)
		)
	)
	(zone
		(layer "F.Cu")
		(hatch none 0.5)
		(connect_pads
			(clearance 0)
		)
		(min_thickness 0.25)
		(keepout
			(tracks allowed)
			(vias allowed)
			(pads allowed)
			(copperpour allowed)
			(footprints allowed)
		)
		(placement
			(enabled no)
			(sheetname "")
		)
		(fill
			(thermal_gap 0.5)
			(thermal_bridge_width 0.5)
			(island_removal_mode 0)
		)
		(polygon
			(pts
				(xy 411.87497 -276.056852) (xy 409.84297 -276.056852) (xy 409.84297 -276.054566) (xy 409.664154 -276.054566)
				(xy 409.473908 -276.054566) (xy 409.473908 -275.77415) (xy 409.344368 -275.77415) (xy 409.344368 -275.264626)
				(xy 409.555696 -275.264626) (xy 411.967172 -275.264626) (xy 412.017464 -275.264626) (xy 412.017464 -275.280628)
				(xy 412.017464 -276.056852) (xy 412.011114 -276.056852)
			)
		)
	)
	(zone
		(layer "F.Cu")
		(hatch none 0.5)
		(connect_pads
			(clearance 0)
		)
		(min_thickness 0.25)
		(keepout
			(tracks allowed)
			(vias allowed)
			(pads allowed)
			(copperpour allowed)
			(footprints allowed)
		)
		(placement
			(enabled no)
			(sheetname "")
		)
		(fill
			(thermal_gap 0.5)
			(thermal_bridge_width 0.5)
			(island_removal_mode 0)
		)
		(polygon
			(pts
				(xy 304.319178 -288.06648) (xy 304.319178 -287.622742) (xy 306.644294 -287.622742) (xy 306.644294 -288.06648)
			)
		)
	)
	(zone
		(layer "F.Cu")
		(hatch none 0.5)
		(connect_pads
			(clearance 0)
		)
		(min_thickness 0.25)
		(keepout
			(tracks allowed)
			(vias allowed)
			(pads allowed)
			(copperpour allowed)
			(footprints allowed)
		)
		(placement
			(enabled no)
			(sheetname "")
		)
		(fill
			(thermal_gap 0.5)
			(thermal_bridge_width 0.5)
			(island_removal_mode 0)
		)
		(polygon
			(pts
				(xy 333.78394 -253.500128) (xy 333.78394 -253.083568) (xy 334.3656 -253.083568) (xy 334.3656 -253.500128)
			)
		)
	)
	(zone
		(layer "F.Cu")
		(hatch none 0.5)
		(connect_pads
			(clearance 0)
		)
		(min_thickness 0.25)
		(keepout
			(tracks allowed)
			(vias allowed)
			(pads allowed)
			(copperpour allowed)
			(footprints allowed)
		)
		(placement
			(enabled no)
			(sheetname "")
		)
		(fill
			(thermal_gap 0.5)
			(thermal_bridge_width 0.5)
			(island_removal_mode 0)
		)
		(polygon
			(pts
				(xy 161.891726 -270.726408) (xy 163.923726 -270.726408) (xy 163.923726 -270.728694) (xy 164.102542 -270.728694)
				(xy 164.102542 -270.96593) (xy 164.240464 -270.96593) (xy 164.283644 -271.00911) (xy 164.283644 -271.141952)
				(xy 164.283644 -271.44599) (xy 164.211 -271.518634) (xy 161.670746 -271.518634) (xy 161.529522 -271.37741)
				(xy 161.529522 -271.180306) (xy 161.611056 -271.098772) (xy 161.611056 -270.726408) (xy 161.708592 -270.726408)
				(xy 161.755582 -270.726408)
			)
		)
	)
	(zone
		(layer "F.Cu")
		(hatch none 0.5)
		(connect_pads
			(clearance 0)
		)
		(min_thickness 0.25)
		(keepout
			(tracks allowed)
			(vias allowed)
			(pads allowed)
			(copperpour allowed)
			(footprints allowed)
		)
		(placement
			(enabled no)
			(sheetname "")
		)
		(fill
			(thermal_gap 0.5)
			(thermal_bridge_width 0.5)
			(island_removal_mode 0)
		)
		(polygon
			(pts
				(xy 85.31352 -284.975808) (xy 85.60054 -284.975808) (xy 85.63102 -284.945328) (xy 85.63102 -284.317948)
				(xy 85.54466 -284.231588) (xy 85.3567 -284.231588) (xy 85.28304 -284.305248) (xy 85.28304 -284.945328)
			)
		)
	)
	(zone
		(layer "F.Cu")
		(hatch none 0.5)
		(connect_pads
			(clearance 0)
		)
		(min_thickness 0.25)
		(keepout
			(tracks allowed)
			(vias allowed)
			(pads allowed)
			(copperpour allowed)
			(footprints allowed)
		)
		(placement
			(enabled no)
			(sheetname "")
		)
		(fill
			(thermal_gap 0.5)
			(thermal_bridge_width 0.5)
			(island_removal_mode 0)
		)
		(polygon
			(pts
				(xy 57.307734 -20.10791) (xy 57.307734 -16.973296) (xy 59.086496 -16.973296) (xy 59.086496 -20.10791)
			)
		)
	)
	(zone
		(layer "F.Cu")
		(hatch none 0.5)
		(connect_pads
			(clearance 0)
		)
		(min_thickness 0.25)
		(keepout
			(tracks allowed)
			(vias allowed)
			(pads allowed)
			(copperpour allowed)
			(footprints not_allowed)
		)
		(placement
			(enabled no)
			(sheetname "")
		)
		(fill
			(thermal_gap 0.5)
			(thermal_bridge_width 0.5)
			(island_removal_mode 0)
		)
		(polygon
			(pts
				(xy 320.437256 -168.661842) (xy 254.130048 -168.661842) (xy 254.130048 -185.091832) (xy 314.987178 -185.091832)
				(xy 314.987178 -187.661804) (xy 320.437256 -187.661804)
			)
		)
	)
	(zone
		(layer "F.Cu")
		(hatch none 0.5)
		(connect_pads
			(clearance 0)
		)
		(min_thickness 0.25)
		(keepout
			(tracks allowed)
			(vias allowed)
			(pads allowed)
			(copperpour allowed)
			(footprints allowed)
		)
		(placement
			(enabled no)
			(sheetname "")
		)
		(fill
			(thermal_gap 0.5)
			(thermal_bridge_width 0.5)
			(island_removal_mode 0)
		)
		(polygon
			(pts
				(xy 176.979326 -200.407016) (xy 179.011326 -200.407016) (xy 179.011326 -200.178416) (xy 176.979326 -200.178416)
				(xy 176.848008 -200.178416) (xy 176.8221 -200.178416) (xy 176.8221 -200.407016) (xy 176.848008 -200.407016)
			)
		)
	)
	(zone
		(layer "F.Cu")
		(hatch none 0.5)
		(connect_pads
			(clearance 0)
		)
		(min_thickness 0.25)
		(keepout
			(tracks allowed)
			(vias allowed)
			(pads allowed)
			(copperpour allowed)
			(footprints allowed)
		)
		(placement
			(enabled no)
			(sheetname "")
		)
		(fill
			(thermal_gap 0.5)
			(thermal_bridge_width 0.5)
			(island_removal_mode 0)
		)
		(polygon
			(pts
				(xy 307.85308 -244.716554) (xy 307.85308 -244.272816) (xy 310.01208 -244.272816) (xy 310.072786 -244.272816)
				(xy 310.072786 -244.716554) (xy 310.01208 -244.716554)
			)
		)
	)
	(zone
		(layer "F.Cu")
		(hatch none 0.5)
		(connect_pads
			(clearance 0)
		)
		(min_thickness 0.25)
		(keepout
			(tracks allowed)
			(vias allowed)
			(pads allowed)
			(copperpour allowed)
			(footprints allowed)
		)
		(placement
			(enabled no)
			(sheetname "")
		)
		(fill
			(thermal_gap 0.5)
			(thermal_bridge_width 0.5)
			(island_removal_mode 0)
		)
		(polygon
			(pts
				(xy 192.066926 -286.026352) (xy 194.098926 -286.026352) (xy 194.098926 -286.254952) (xy 192.066926 -286.254952)
				(xy 191.930782 -286.254952) (xy 191.883792 -286.254952) (xy 191.883792 -286.026352) (xy 191.930782 -286.026352)
			)
		)
	)
	(zone
		(layer "F.Cu")
		(hatch none 0.5)
		(connect_pads
			(clearance 0)
		)
		(min_thickness 0.25)
		(keepout
			(tracks allowed)
			(vias allowed)
			(pads allowed)
			(copperpour allowed)
			(footprints allowed)
		)
		(placement
			(enabled no)
			(sheetname "")
		)
		(fill
			(thermal_gap 0.5)
			(thermal_bridge_width 0.5)
			(island_removal_mode 0)
		)
		(polygon
			(pts
				(xy 349.471742 -404.802594) (xy 349.471742 -399.959576) (xy 351.356168 -399.959576) (xy 351.356168 -404.802594)
			)
		)
	)
	(zone
		(layer "F.Cu")
		(hatch none 0.5)
		(connect_pads
			(clearance 0)
		)
		(min_thickness 0.25)
		(keepout
			(tracks allowed)
			(vias allowed)
			(pads allowed)
			(copperpour allowed)
			(footprints allowed)
		)
		(placement
			(enabled no)
			(sheetname "")
		)
		(fill
			(thermal_gap 0.5)
			(thermal_bridge_width 0.5)
			(island_removal_mode 0)
		)
		(polygon
			(pts
				(xy 56.37911 -234.922822) (xy 58.704226 -234.922822) (xy 58.98388 -234.922822) (xy 58.98388 -235.864908)
				(xy 56.044338 -235.864908) (xy 56.044338 -234.922822)
			)
		)
	)
	(zone
		(layer "F.Cu")
		(hatch none 0.5)
		(connect_pads
			(clearance 0)
		)
		(min_thickness 0.25)
		(keepout
			(tracks allowed)
			(vias allowed)
			(pads allowed)
			(copperpour allowed)
			(footprints allowed)
		)
		(placement
			(enabled no)
			(sheetname "")
		)
		(fill
			(thermal_gap 0.5)
			(thermal_bridge_width 0.5)
			(island_removal_mode 0)
		)
		(polygon
			(pts
				(xy 41.29151 -226.016566) (xy 41.29151 -225.572828) (xy 43.616626 -225.572828) (xy 43.616626 -226.016566)
			)
		)
	)
	(zone
		(layer "F.Cu")
		(hatch none 0.5)
		(connect_pads
			(clearance 0)
		)
		(min_thickness 0.25)
		(keepout
			(tracks allowed)
			(vias allowed)
			(pads allowed)
			(copperpour allowed)
			(footprints not_allowed)
		)
		(placement
			(enabled no)
			(sheetname "")
		)
		(fill
			(thermal_gap 0.5)
			(thermal_bridge_width 0.5)
			(island_removal_mode 0)
		)
		(polygon
			(pts
				(arc
					(start 201.895456 -51.999896)
					(mid 204.645514 -49.249838)
					(end 207.395318 -51.999896)
				)
				(arc
					(start 207.395318 -51.999896)
					(mid 204.645514 -54.7497)
					(end 201.895456 -51.999896)
				)
			)
		)
	)
	(zone
		(layer "F.Cu")
		(hatch none 0.5)
		(connect_pads
			(clearance 0)
		)
		(min_thickness 0.25)
		(keepout
			(tracks allowed)
			(vias allowed)
			(pads allowed)
			(copperpour allowed)
			(footprints allowed)
		)
		(placement
			(enabled no)
			(sheetname "")
		)
		(fill
			(thermal_gap 0.5)
			(thermal_bridge_width 0.5)
			(island_removal_mode 0)
		)
		(polygon
			(pts
				(xy 405.731726 -297.304968) (xy 405.731726 -297.076368) (xy 407.763726 -297.076368) (xy 407.763726 -297.304968)
			)
		)
	)
	(zone
		(layer "F.Cu")
		(hatch none 0.5)
		(connect_pads
			(clearance 0)
		)
		(min_thickness 0.25)
		(keepout
			(tracks allowed)
			(vias allowed)
			(pads allowed)
			(copperpour allowed)
			(footprints allowed)
		)
		(placement
			(enabled no)
			(sheetname "")
		)
		(fill
			(thermal_gap 0.5)
			(thermal_bridge_width 0.5)
			(island_removal_mode 0)
		)
		(polygon
			(pts
				(xy 41.29151 -316.116462) (xy 41.29151 -315.672724) (xy 43.616626 -315.672724) (xy 43.616626 -316.116462)
			)
		)
	)
	(zone
		(layer "F.Cu")
		(hatch none 0.5)
		(connect_pads
			(clearance 0)
		)
		(min_thickness 0.25)
		(keepout
			(tracks allowed)
			(vias allowed)
			(pads allowed)
			(copperpour allowed)
			(footprints not_allowed)
		)
		(placement
			(enabled no)
			(sheetname "")
		)
		(fill
			(thermal_gap 0.5)
			(thermal_bridge_width 0.5)
			(island_removal_mode 0)
		)
		(polygon
			(pts
				(arc
					(start 244.650006 -352.49993)
					(mid 236.650022 -360.499914)
					(end 228.650038 -352.49993)
				)
				(arc
					(start 228.650038 -352.49993)
					(mid 236.650022 -344.499946)
					(end 244.650006 -352.49993)
				)
			)
		)
	)
	(zone
		(layer "F.Cu")
		(hatch none 0.5)
		(connect_pads
			(clearance 0)
		)
		(min_thickness 0.25)
		(keepout
			(tracks allowed)
			(vias allowed)
			(pads allowed)
			(copperpour allowed)
			(footprints allowed)
		)
		(placement
			(enabled no)
			(sheetname "")
		)
		(fill
			(thermal_gap 0.5)
			(thermal_bridge_width 0.5)
			(island_removal_mode 0)
		)
		(polygon
			(pts
				(xy 165.335458 -248.854976) (xy 165.335458 -248.626376) (xy 167.367458 -248.626376) (xy 167.367458 -248.854976)
			)
		)
	)
	(zone
		(layer "F.Cu")
		(hatch none 0.5)
		(connect_pads
			(clearance 0)
		)
		(min_thickness 0.25)
		(keepout
			(tracks allowed)
			(vias allowed)
			(pads allowed)
			(copperpour allowed)
			(footprints allowed)
		)
		(placement
			(enabled no)
			(sheetname "")
		)
		(fill
			(thermal_gap 0.5)
			(thermal_bridge_width 0.5)
			(island_removal_mode 0)
		)
		(polygon
			(pts
				(xy 214.4395 -55.263288) (xy 214.4395 -53.665628) (xy 216.06002 -53.665628) (xy 216.06002 -55.263288)
			)
		)
	)
	(zone
		(layer "F.Cu")
		(hatch none 0.5)
		(connect_pads
			(clearance 0)
		)
		(min_thickness 0.25)
		(keepout
			(tracks allowed)
			(vias allowed)
			(pads allowed)
			(copperpour allowed)
			(footprints allowed)
		)
		(placement
			(enabled no)
			(sheetname "")
		)
		(fill
			(thermal_gap 0.5)
			(thermal_bridge_width 0.5)
			(island_removal_mode 0)
		)
		(polygon
			(pts
				(xy 311.91708 -203.06665) (xy 311.91708 -202.622912) (xy 314.15228 -202.622912) (xy 314.15228 -203.06665)
			)
		)
	)
	(zone
		(layer "F.Cu")
		(hatch none 0.5)
		(connect_pads
			(clearance 0)
		)
		(min_thickness 0.25)
		(keepout
			(tracks not_allowed)
			(vias allowed)
			(pads allowed)
			(copperpour not_allowed)
			(footprints allowed)
		)
		(placement
			(enabled no)
			(sheetname "")
		)
		(fill
			(thermal_gap 0.5)
			(thermal_bridge_width 0.5)
			(island_removal_mode 0)
		)
		(polygon
			(pts
				(xy 334.73263 -337.439508) (xy 334.974946 -337.439508) (xy 334.974946 -337.372706) (xy 335.53654 -337.372706)
				(xy 335.53654 -337.048348) (xy 335.826354 -337.048348) (xy 335.826354 -336.47126) (xy 335.73212 -336.377026)
				(xy 334.276954 -336.377026) (xy 334.276954 -336.833718) (xy 334.97266 -336.833718) (xy 334.97266 -336.67319)
				(xy 335.53146 -336.67319) (xy 335.53146 -337.07959) (xy 334.97266 -337.07959) (xy 334.97266 -336.859118)
				(xy 334.276954 -336.859118) (xy 334.276954 -336.986118) (xy 334.73263 -336.986118)
			)
		)
	)
	(zone
		(layer "F.Cu")
		(hatch none 0.5)
		(connect_pads
			(clearance 0)
		)
		(min_thickness 0.25)
		(keepout
			(tracks allowed)
			(vias allowed)
			(pads allowed)
			(copperpour allowed)
			(footprints allowed)
		)
		(placement
			(enabled no)
			(sheetname "")
		)
		(fill
			(thermal_gap 0.5)
			(thermal_bridge_width 0.5)
			(island_removal_mode 0)
		)
		(polygon
			(pts
				(xy 443.450726 -282.005024) (xy 443.450726 -281.776424) (xy 445.482726 -281.776424) (xy 445.482726 -282.005024)
			)
		)
	)
	(zone
		(layer "F.Cu")
		(hatch none 0.5)
		(connect_pads
			(clearance 0)
		)
		(min_thickness 0.25)
		(keepout
			(tracks allowed)
			(vias allowed)
			(pads allowed)
			(copperpour allowed)
			(footprints allowed)
		)
		(placement
			(enabled no)
			(sheetname "")
		)
		(fill
			(thermal_gap 0.5)
			(thermal_bridge_width 0.5)
			(island_removal_mode 0)
		)
		(polygon
			(pts
				(xy 180.423058 -308.354984) (xy 180.423058 -308.126384) (xy 182.455058 -308.126384) (xy 182.455058 -308.354984)
			)
		)
	)
	(zone
		(layer "F.Cu")
		(hatch none 0.5)
		(connect_pads
			(clearance 0)
		)
		(min_thickness 0.25)
		(keepout
			(tracks allowed)
			(vias allowed)
			(pads allowed)
			(copperpour allowed)
			(footprints not_allowed)
		)
		(placement
			(enabled no)
			(sheetname "")
		)
		(fill
			(thermal_gap 0.5)
			(thermal_bridge_width 0.5)
			(island_removal_mode 0)
		)
		(polygon
			(pts
				(arc
					(start 458.659992 -347.700092)
					(mid 461.460088 -344.899996)
					(end 464.25993 -347.700092)
				)
				(arc
					(start 464.25993 -347.700092)
					(mid 461.460088 -350.499934)
					(end 458.659992 -347.700092)
				)
			)
		)
	)
	(zone
		(layer "F.Cu")
		(hatch none 0.5)
		(connect_pads
			(clearance 0)
		)
		(min_thickness 0.25)
		(keepout
			(tracks allowed)
			(vias allowed)
			(pads allowed)
			(copperpour allowed)
			(footprints allowed)
		)
		(placement
			(enabled no)
			(sheetname "")
		)
		(fill
			(thermal_gap 0.5)
			(thermal_bridge_width 0.5)
			(island_removal_mode 0)
		)
		(polygon
			(pts
				(xy 262.50011 -283.816552) (xy 262.50011 -283.372814) (xy 264.825226 -283.372814) (xy 264.825226 -283.816552)
			)
		)
	)
	(zone
		(layer "F.Cu")
		(hatch none 0.5)
		(connect_pads
			(clearance 0)
		)
		(min_thickness 0.25)
		(keepout
			(tracks allowed)
			(vias allowed)
			(pads allowed)
			(copperpour allowed)
			(footprints allowed)
		)
		(placement
			(enabled no)
			(sheetname "")
		)
		(fill
			(thermal_gap 0.5)
			(thermal_bridge_width 0.5)
			(island_removal_mode 0)
		)
		(polygon
			(pts
				(xy 160.866328 -410.948886) (xy 160.866328 -406.105868) (xy 162.750754 -406.105868) (xy 162.750754 -410.948886)
			)
		)
	)
	(zone
		(layer "F.Cu")
		(hatch none 0.5)
		(connect_pads
			(clearance 0)
		)
		(min_thickness 0.25)
		(keepout
			(tracks allowed)
			(vias allowed)
			(pads allowed)
			(copperpour allowed)
			(footprints not_allowed)
		)
		(placement
			(enabled no)
			(sheetname "")
		)
		(fill
			(thermal_gap 0.5)
			(thermal_bridge_width 0.5)
			(island_removal_mode 0)
		)
		(polygon
			(pts
				(xy 391.152888 -67.655186) (xy 398.646904 -67.655186) (xy 398.646904 -46.344586) (xy 391.152888 -46.344586)
			)
		)
	)
	(zone
		(layer "F.Cu")
		(hatch none 0.5)
		(connect_pads
			(clearance 0)
		)
		(min_thickness 0.25)
		(keepout
			(tracks allowed)
			(vias allowed)
			(pads allowed)
			(copperpour allowed)
			(footprints allowed)
		)
		(placement
			(enabled no)
			(sheetname "")
		)
		(fill
			(thermal_gap 0.5)
			(thermal_bridge_width 0.5)
			(island_removal_mode 0)
		)
		(polygon
			(pts
				(xy 26.20391 -248.966482) (xy 26.20391 -248.522744) (xy 28.529026 -248.522744) (xy 28.529026 -248.966482)
			)
		)
	)
	(zone
		(layer "F.Cu")
		(hatch none 0.5)
		(connect_pads
			(clearance 0)
		)
		(min_thickness 0.25)
		(keepout
			(tracks allowed)
			(vias allowed)
			(pads allowed)
			(copperpour allowed)
			(footprints allowed)
		)
		(placement
			(enabled no)
			(sheetname "")
		)
		(fill
			(thermal_gap 0.5)
			(thermal_bridge_width 0.5)
			(island_removal_mode 0)
		)
		(polygon
			(pts
				(xy 311.91708 -222.616522) (xy 311.91708 -222.172784) (xy 314.12688 -222.172784) (xy 314.12688 -222.616522)
			)
		)
	)
	(zone
		(layer "F.Cu")
		(hatch none 0.5)
		(connect_pads
			(clearance 0)
		)
		(min_thickness 0.25)
		(keepout
			(tracks allowed)
			(vias allowed)
			(pads allowed)
			(copperpour allowed)
			(footprints allowed)
		)
		(placement
			(enabled no)
			(sheetname "")
		)
		(fill
			(thermal_gap 0.5)
			(thermal_bridge_width 0.5)
			(island_removal_mode 0)
		)
		(polygon
			(pts
				(xy 259.056378 -277.016464) (xy 259.056378 -276.572726) (xy 261.381494 -276.572726) (xy 261.381494 -277.016464)
			)
		)
	)
	(zone
		(layer "F.Cu")
		(hatch none 0.5)
		(connect_pads
			(clearance 0)
		)
		(min_thickness 0.25)
		(keepout
			(tracks allowed)
			(vias allowed)
			(pads allowed)
			(copperpour allowed)
			(footprints allowed)
		)
		(placement
			(enabled no)
			(sheetname "")
		)
		(fill
			(thermal_gap 0.5)
			(thermal_bridge_width 0.5)
			(island_removal_mode 0)
		)
		(polygon
			(pts
				(xy 56.37911 -228.566472) (xy 56.37911 -228.122734) (xy 58.704226 -228.122734) (xy 58.704226 -228.566472)
			)
		)
	)
	(zone
		(layer "F.Cu")
		(hatch none 0.5)
		(connect_pads
			(clearance 0)
		)
		(min_thickness 0.25)
		(keepout
			(tracks allowed)
			(vias allowed)
			(pads allowed)
			(copperpour allowed)
			(footprints allowed)
		)
		(placement
			(enabled no)
			(sheetname "")
		)
		(fill
			(thermal_gap 0.5)
			(thermal_bridge_width 0.5)
			(island_removal_mode 0)
		)
		(polygon
			(pts
				(xy 165.335458 -273.276314) (xy 167.367458 -273.276314) (xy 167.367458 -273.2786) (xy 167.546274 -273.2786)
				(xy 167.73652 -273.2786) (xy 167.804084 -273.2786) (xy 167.804084 -273.559016) (xy 167.86606 -273.559016)
				(xy 167.86606 -274.06854) (xy 167.654732 -274.06854) (xy 165.114478 -274.06854) (xy 164.854636 -274.06854)
				(xy 164.848032 -274.06854) (xy 164.848032 -273.591782) (xy 164.972238 -273.591782) (xy 164.972238 -273.276314)
				(xy 165.010846 -273.276314) (xy 165.054788 -273.276314) (xy 165.152324 -273.276314) (xy 165.199314 -273.276314)
			)
		)
	)
	(zone
		(layer "F.Cu")
		(hatch none 0.5)
		(connect_pads
			(clearance 0)
		)
		(min_thickness 0.25)
		(keepout
			(tracks allowed)
			(vias allowed)
			(pads allowed)
			(copperpour allowed)
			(footprints allowed)
		)
		(placement
			(enabled no)
			(sheetname "")
		)
		(fill
			(thermal_gap 0.5)
			(thermal_bridge_width 0.5)
			(island_removal_mode 0)
		)
		(polygon
			(pts
				(xy 41.29151 -224.316544) (xy 41.29151 -223.872806) (xy 43.616626 -223.872806) (xy 43.616626 -224.316544)
			)
		)
	)
	(zone
		(layer "F.Cu")
		(hatch none 0.5)
		(connect_pads
			(clearance 0)
		)
		(min_thickness 0.25)
		(keepout
			(tracks allowed)
			(vias allowed)
			(pads allowed)
			(copperpour allowed)
			(footprints allowed)
		)
		(placement
			(enabled no)
			(sheetname "")
		)
		(fill
			(thermal_gap 0.5)
			(thermal_bridge_width 0.5)
			(island_removal_mode 0)
		)
		(polygon
			(pts
				(xy 304.319178 -316.116462) (xy 304.319178 -315.672724) (xy 306.644294 -315.672724) (xy 306.644294 -316.116462)
			)
		)
	)
	(zone
		(layer "F.Cu")
		(hatch none 0.5)
		(connect_pads
			(clearance 0)
		)
		(min_thickness 0.25)
		(keepout
			(tracks allowed)
			(vias allowed)
			(pads allowed)
			(copperpour allowed)
			(footprints allowed)
		)
		(placement
			(enabled no)
			(sheetname "")
		)
		(fill
			(thermal_gap 0.5)
			(thermal_bridge_width 0.5)
			(island_removal_mode 0)
		)
		(polygon
			(pts
				(xy 176.979326 -219.107004) (xy 179.011326 -219.107004) (xy 179.011326 -218.878404) (xy 176.979326 -218.878404)
				(xy 176.848008 -218.878404) (xy 176.8221 -218.878404) (xy 176.8221 -219.107004) (xy 176.848008 -219.107004)
			)
		)
	)
	(zone
		(layer "F.Cu")
		(hatch none 0.5)
		(connect_pads
			(clearance 0)
		)
		(min_thickness 0.25)
		(keepout
			(tracks allowed)
			(vias allowed)
			(pads allowed)
			(copperpour allowed)
			(footprints allowed)
		)
		(placement
			(enabled no)
			(sheetname "")
		)
		(fill
			(thermal_gap 0.5)
			(thermal_bridge_width 0.5)
			(island_removal_mode 0)
		)
		(polygon
			(pts
				(xy 413.275526 -216.554812) (xy 413.275526 -216.326212) (xy 415.307526 -216.326212) (xy 415.307526 -216.554812)
			)
		)
	)
	(zone
		(layer "F.Cu")
		(hatch none 0.5)
		(connect_pads
			(clearance 0)
		)
		(min_thickness 0.25)
		(keepout
			(tracks allowed)
			(vias allowed)
			(pads allowed)
			(copperpour allowed)
			(footprints allowed)
		)
		(placement
			(enabled no)
			(sheetname "")
		)
		(fill
			(thermal_gap 0.5)
			(thermal_bridge_width 0.5)
			(island_removal_mode 0)
		)
		(polygon
			(pts
				(xy 391.64768 -12.748768) (xy 391.64768 -9.710928) (xy 407.81478 -9.710928) (xy 407.81478 -12.748768)
			)
		)
	)
	(zone
		(layer "F.Cu")
		(hatch none 0.5)
		(connect_pads
			(clearance 0)
		)
		(min_thickness 0.25)
		(keepout
			(tracks allowed)
			(vias allowed)
			(pads allowed)
			(copperpour allowed)
			(footprints allowed)
		)
		(placement
			(enabled no)
			(sheetname "")
		)
		(fill
			(thermal_gap 0.5)
			(thermal_bridge_width 0.5)
			(island_removal_mode 0)
		)
		(polygon
			(pts
				(xy 332.210156 -234.146852) (xy 332.413102 -234.349798) (xy 332.456028 -234.349798) (xy 332.899766 -233.906314)
				(xy 332.899766 -233.78414) (xy 332.766924 -233.651044) (xy 332.662784 -233.651044) (xy 332.210156 -234.103672)
			)
		)
	)
	(zone
		(layer "F.Cu")
		(hatch none 0.5)
		(connect_pads
			(clearance 0)
		)
		(min_thickness 0.25)
		(keepout
			(tracks allowed)
			(vias allowed)
			(pads allowed)
			(copperpour allowed)
			(footprints allowed)
		)
		(placement
			(enabled no)
			(sheetname "")
		)
		(fill
			(thermal_gap 0.5)
			(thermal_bridge_width 0.5)
			(island_removal_mode 0)
		)
		(polygon
			(pts
				(xy 14.560042 -248.966482) (xy 14.560042 -248.522744) (xy 16.885158 -248.522744) (xy 16.885158 -248.966482)
			)
		)
	)
	(zone
		(layer "F.Cu")
		(hatch none 0.5)
		(connect_pads
			(clearance 0)
		)
		(min_thickness 0.25)
		(keepout
			(tracks allowed)
			(vias allowed)
			(pads allowed)
			(copperpour allowed)
			(footprints allowed)
		)
		(placement
			(enabled no)
			(sheetname "")
		)
		(fill
			(thermal_gap 0.5)
			(thermal_bridge_width 0.5)
			(island_removal_mode 0)
		)
		(polygon
			(pts
				(xy 384.855466 -342.109298) (xy 383.039366 -342.109298) (xy 383.039366 -340.730078) (xy 384.855466 -340.730078)
			)
		)
	)
	(zone
		(layer "F.Cu")
		(hatch none 0.5)
		(connect_pads
			(clearance 0)
		)
		(min_thickness 0.25)
		(keepout
			(tracks not_allowed)
			(vias allowed)
			(pads allowed)
			(copperpour not_allowed)
			(footprints allowed)
		)
		(placement
			(enabled no)
			(sheetname "")
		)
		(fill
			(thermal_gap 0.5)
			(thermal_bridge_width 0.5)
			(island_removal_mode 0)
		)
		(polygon
			(pts
				(xy 423.804334 -363.687868) (xy 424.04665 -363.687868) (xy 424.04665 -362.867448) (xy 423.804334 -362.867448)
			)
		)
	)
	(zone
		(layer "F.Cu")
		(hatch none 0.5)
		(connect_pads
			(clearance 0)
		)
		(min_thickness 0.25)
		(keepout
			(tracks allowed)
			(vias allowed)
			(pads allowed)
			(copperpour allowed)
			(footprints not_allowed)
		)
		(placement
			(enabled no)
			(sheetname "")
		)
		(fill
			(thermal_gap 0.5)
			(thermal_bridge_width 0.5)
			(island_removal_mode 0)
		)
		(polygon
			(pts
				(xy 294.900096 -45.150024) (xy 294.900096 -22.850094) (xy 271.040606 -22.850094) (xy 271.040606 -45.150024)
			)
		)
	)
	(zone
		(layer "F.Cu")
		(hatch none 0.5)
		(connect_pads
			(clearance 0)
		)
		(min_thickness 0.25)
		(keepout
			(tracks allowed)
			(vias allowed)
			(pads allowed)
			(copperpour allowed)
			(footprints allowed)
		)
		(placement
			(enabled no)
			(sheetname "")
		)
		(fill
			(thermal_gap 0.5)
			(thermal_bridge_width 0.5)
			(island_removal_mode 0)
		)
		(polygon
			(pts
				(xy 315.199268 -366.12195) (xy 315.598048 -365.72317) (xy 315.598048 -364.03407) (xy 315.420248 -363.85627)
				(xy 311.282588 -363.85627) (xy 311.127648 -364.01121) (xy 311.127648 -365.88065) (xy 311.368948 -366.12195)
			)
		)
	)
	(zone
		(layer "F.Cu")
		(hatch none 0.5)
		(connect_pads
			(clearance 0)
		)
		(min_thickness 0.25)
		(keepout
			(tracks allowed)
			(vias allowed)
			(pads allowed)
			(copperpour allowed)
			(footprints not_allowed)
		)
		(placement
			(enabled no)
			(sheetname "")
		)
		(fill
			(thermal_gap 0.5)
			(thermal_bridge_width 0.5)
			(island_removal_mode 0)
		)
		(polygon
			(pts
				(arc
					(start 317.90005 -160.50006)
					(mid 322.90004 -155.50007)
					(end 327.90003 -160.50006)
				)
				(arc
					(start 327.90003 -160.50006)
					(mid 322.90004 -165.50005)
					(end 317.90005 -160.50006)
				)
			)
		)
	)
	(zone
		(layer "F.Cu")
		(hatch none 0.5)
		(connect_pads
			(clearance 0)
		)
		(min_thickness 0.25)
		(keepout
			(tracks allowed)
			(vias allowed)
			(pads allowed)
			(copperpour allowed)
			(footprints allowed)
		)
		(placement
			(enabled no)
			(sheetname "")
		)
		(fill
			(thermal_gap 0.5)
			(thermal_bridge_width 0.5)
			(island_removal_mode 0)
		)
		(polygon
			(pts
				(xy 207.154526 -314.076334) (xy 209.186526 -314.076334) (xy 209.186526 -314.304934) (xy 207.154526 -314.304934)
				(xy 207.018382 -314.304934) (xy 206.971392 -314.304934) (xy 206.971392 -314.076334) (xy 207.018382 -314.076334)
			)
		)
	)
	(zone
		(layer "F.Cu")
		(hatch none 0.5)
		(connect_pads
			(clearance 0)
		)
		(min_thickness 0.25)
		(keepout
			(tracks allowed)
			(vias allowed)
			(pads allowed)
			(copperpour allowed)
			(footprints allowed)
		)
		(placement
			(enabled no)
			(sheetname "")
		)
		(fill
			(thermal_gap 0.5)
			(thermal_bridge_width 0.5)
			(island_removal_mode 0)
		)
		(polygon
			(pts
				(xy 458.538326 -310.90489) (xy 458.538326 -310.67629) (xy 460.570326 -310.67629) (xy 460.570326 -310.90489)
			)
		)
	)
	(zone
		(layer "F.Cu")
		(hatch none 0.5)
		(connect_pads
			(clearance 0)
		)
		(min_thickness 0.25)
		(keepout
			(tracks allowed)
			(vias allowed)
			(pads allowed)
			(copperpour allowed)
			(footprints allowed)
		)
		(placement
			(enabled no)
			(sheetname "")
		)
		(fill
			(thermal_gap 0.5)
			(thermal_bridge_width 0.5)
			(island_removal_mode 0)
		)
		(polygon
			(pts
				(xy 292.67531 -240.466626) (xy 292.67531 -240.022888) (xy 295.000426 -240.022888) (xy 295.000426 -240.466626)
			)
		)
	)
	(zone
		(layer "F.Cu")
		(hatch none 0.5)
		(connect_pads
			(clearance 0)
		)
		(min_thickness 0.25)
		(keepout
			(tracks allowed)
			(vias allowed)
			(pads allowed)
			(copperpour allowed)
			(footprints allowed)
		)
		(placement
			(enabled no)
			(sheetname "")
		)
		(fill
			(thermal_gap 0.5)
			(thermal_bridge_width 0.5)
			(island_removal_mode 0)
		)
		(polygon
			(pts
				(xy 56.37911 -294.01643) (xy 56.37911 -293.572692) (xy 58.704226 -293.572692) (xy 58.704226 -294.01643)
			)
		)
	)
	(zone
		(layer "F.Cu")
		(hatch none 0.5)
		(connect_pads
			(clearance 0)
		)
		(min_thickness 0.25)
		(keepout
			(tracks allowed)
			(vias allowed)
			(pads allowed)
			(copperpour allowed)
			(footprints allowed)
		)
		(placement
			(enabled no)
			(sheetname "")
		)
		(fill
			(thermal_gap 0.5)
			(thermal_bridge_width 0.5)
			(island_removal_mode 0)
		)
		(polygon
			(pts
				(xy 56.37911 -200.51649) (xy 56.37911 -200.072752) (xy 58.704226 -200.072752) (xy 58.704226 -200.51649)
			)
		)
	)
	(zone
		(layer "F.Cu")
		(hatch none 0.5)
		(connect_pads
			(clearance 0)
		)
		(min_thickness 0.25)
		(keepout
			(tracks allowed)
			(vias allowed)
			(pads allowed)
			(copperpour allowed)
			(footprints allowed)
		)
		(placement
			(enabled no)
			(sheetname "")
		)
		(fill
			(thermal_gap 0.5)
			(thermal_bridge_width 0.5)
			(island_removal_mode 0)
		)
		(polygon
			(pts
				(xy 413.275526 -225.904806) (xy 413.275526 -225.676206) (xy 415.307526 -225.676206) (xy 415.307526 -225.904806)
			)
		)
	)
	(zone
		(layer "F.Cu")
		(hatch none 0.5)
		(connect_pads
			(clearance 0)
		)
		(min_thickness 0.25)
		(keepout
			(tracks allowed)
			(vias allowed)
			(pads allowed)
			(copperpour allowed)
			(footprints allowed)
		)
		(placement
			(enabled no)
			(sheetname "")
		)
		(fill
			(thermal_gap 0.5)
			(thermal_bridge_width 0.5)
			(island_removal_mode 0)
		)
		(polygon
			(pts
				(xy 455.094594 -272.42643) (xy 457.126594 -272.42643) (xy 457.126594 -272.65503) (xy 455.094594 -272.65503)
				(xy 454.95845 -272.65503) (xy 454.91146 -272.65503) (xy 454.91146 -272.42643) (xy 454.95845 -272.42643)
			)
		)
	)
	(zone
		(layer "F.Cu")
		(hatch none 0.5)
		(connect_pads
			(clearance 0)
		)
		(min_thickness 0.25)
		(keepout
			(tracks allowed)
			(vias allowed)
			(pads allowed)
			(copperpour allowed)
			(footprints allowed)
		)
		(placement
			(enabled no)
			(sheetname "")
		)
		(fill
			(thermal_gap 0.5)
			(thermal_bridge_width 0.5)
			(island_removal_mode 0)
		)
		(polygon
			(pts
				(xy 125.824488 -404.802594) (xy 125.824488 -399.959576) (xy 127.708914 -399.959576) (xy 127.708914 -404.802594)
			)
		)
	)
	(zone
		(layer "F.Cu")
		(hatch none 0.5)
		(connect_pads
			(clearance 0)
		)
		(min_thickness 0.25)
		(keepout
			(tracks allowed)
			(vias allowed)
			(pads allowed)
			(copperpour allowed)
			(footprints not_allowed)
		)
		(placement
			(enabled no)
			(sheetname "")
		)
		(fill
			(thermal_gap 0.5)
			(thermal_bridge_width 0.5)
			(island_removal_mode 0)
		)
		(polygon
			(pts
				(arc
					(start 194.015868 -440.989974)
					(mid 194.510079 -440.047498)
					(end 195.50507 -439.669936)
				)
				(xy 196.004942 -439.669936) (xy 196.004942 -424.126914) (xy 275.815044 -424.126914) (xy 275.815044 -439.669936)
				(arc
					(start 276.314916 -439.669936)
					(mid 277.309956 -440.047443)
					(end 277.804118 -440.989974)
				)
				(arc
					(start 287.638236 -440.989974)
					(mid 286.090364 -438.490221)
					(end 285.550102 -435.600094)
				)
				(arc
					(start 285.550102 -435.600094)
					(mid 285.653339 -434.318499)
					(end 285.960566 -433.07)
				)
				(xy 281.480006 -433.07) (xy 281.480006 -398.75587) (xy 189.33922 -398.75587) (xy 189.33922 -403.770084)
				(xy 190.339218 -403.770084) (xy 190.339218 -433.07)
				(arc
					(start 187.339478 -433.07)
					(mid 187.576306 -437.257907)
					(end 185.661554 -440.989974)
				)
			)
		)
	)
	(zone
		(layer "F.Cu")
		(hatch none 0.5)
		(connect_pads
			(clearance 0)
		)
		(min_thickness 0.25)
		(keepout
			(tracks allowed)
			(vias allowed)
			(pads allowed)
			(copperpour allowed)
			(footprints allowed)
		)
		(placement
			(enabled no)
			(sheetname "")
		)
		(fill
			(thermal_gap 0.5)
			(thermal_bridge_width 0.5)
			(island_removal_mode 0)
		)
		(polygon
			(pts
				(xy 307.76291 -277.422864) (xy 310.088026 -277.422864) (xy 310.108854 -277.422864) (xy 310.108854 -278.406352)
				(xy 307.652674 -278.406352) (xy 307.652674 -277.422864)
			)
		)
	)
	(zone
		(layer "F.Cu")
		(hatch none 0.5)
		(connect_pads
			(clearance 0)
		)
		(min_thickness 0.25)
		(keepout
			(tracks allowed)
			(vias allowed)
			(pads allowed)
			(copperpour allowed)
			(footprints allowed)
		)
		(placement
			(enabled no)
			(sheetname "")
		)
		(fill
			(thermal_gap 0.5)
			(thermal_bridge_width 0.5)
			(island_removal_mode 0)
		)
		(polygon
			(pts
				(xy 94.464886 -331.689456) (xy 94.464886 -335.695036) (xy 94.944946 -336.175096) (xy 97.009966 -336.175096)
				(xy 97.281746 -335.903316) (xy 97.281746 -334.049116) (xy 97.533206 -333.797656) (xy 99.453446 -333.797656)
				(xy 99.870006 -333.381096) (xy 99.870006 -331.890116) (xy 99.222306 -331.242416) (xy 94.911926 -331.242416)
			)
		)
	)
	(zone
		(layer "F.Cu")
		(hatch none 0.5)
		(connect_pads
			(clearance 0)
		)
		(min_thickness 0.25)
		(keepout
			(tracks allowed)
			(vias allowed)
			(pads allowed)
			(copperpour allowed)
			(footprints allowed)
		)
		(placement
			(enabled no)
			(sheetname "")
		)
		(fill
			(thermal_gap 0.5)
			(thermal_bridge_width 0.5)
			(island_removal_mode 0)
		)
		(polygon
			(pts
				(xy 428.363126 -301.554896) (xy 428.363126 -301.326296) (xy 430.395126 -301.326296) (xy 430.395126 -301.554896)
			)
		)
	)
	(zone
		(layer "F.Cu")
		(hatch none 0.5)
		(connect_pads
			(clearance 0)
		)
		(min_thickness 0.25)
		(keepout
			(tracks allowed)
			(vias allowed)
			(pads allowed)
			(copperpour allowed)
			(footprints allowed)
		)
		(placement
			(enabled no)
			(sheetname "")
		)
		(fill
			(thermal_gap 0.5)
			(thermal_bridge_width 0.5)
			(island_removal_mode 0)
		)
		(polygon
			(pts
				(xy 262.50011 -244.716554) (xy 262.50011 -244.272816) (xy 264.825226 -244.272816) (xy 264.825226 -244.716554)
			)
		)
	)
	(zone
		(layer "F.Cu")
		(hatch none 0.5)
		(connect_pads
			(clearance 0)
		)
		(min_thickness 0.25)
		(keepout
			(tracks allowed)
			(vias allowed)
			(pads allowed)
			(copperpour allowed)
			(footprints allowed)
		)
		(placement
			(enabled no)
			(sheetname "")
		)
		(fill
			(thermal_gap 0.5)
			(thermal_bridge_width 0.5)
			(island_removal_mode 0)
		)
		(polygon
			(pts
				(xy 440.006994 -229.07625) (xy 442.038994 -229.07625) (xy 442.038994 -229.30485) (xy 440.006994 -229.30485)
				(xy 439.875676 -229.30485) (xy 439.849768 -229.30485) (xy 439.849768 -229.07625) (xy 439.875676 -229.07625)
			)
		)
	)
	(zone
		(layer "F.Cu")
		(hatch none 0.5)
		(connect_pads
			(clearance 0)
		)
		(min_thickness 0.25)
		(keepout
			(tracks allowed)
			(vias allowed)
			(pads allowed)
			(copperpour allowed)
			(footprints allowed)
		)
		(placement
			(enabled no)
			(sheetname "")
		)
		(fill
			(thermal_gap 0.5)
			(thermal_bridge_width 0.5)
			(island_removal_mode 0)
		)
		(polygon
			(pts
				(xy 207.154526 -291.126418) (xy 209.186526 -291.126418) (xy 209.186526 -291.355018) (xy 207.154526 -291.355018)
				(xy 207.018382 -291.355018) (xy 206.971392 -291.355018) (xy 206.971392 -291.126418) (xy 207.018382 -291.126418)
			)
		)
	)
	(zone
		(layer "F.Cu")
		(hatch none 0.5)
		(connect_pads
			(clearance 0)
		)
		(min_thickness 0.25)
		(keepout
			(tracks allowed)
			(vias allowed)
			(pads allowed)
			(copperpour allowed)
			(footprints allowed)
		)
		(placement
			(enabled no)
			(sheetname "")
		)
		(fill
			(thermal_gap 0.5)
			(thermal_bridge_width 0.5)
			(island_removal_mode 0)
		)
		(polygon
			(pts
				(xy 197.553834 -233.557064) (xy 195.521834 -233.557064) (xy 195.521834 -233.554778) (xy 195.343018 -233.554778)
				(xy 195.343018 -233.317542) (xy 195.205096 -233.317542) (xy 195.161916 -233.274362) (xy 195.161916 -233.14152)
				(xy 195.161916 -232.837482) (xy 195.23456 -232.764838) (xy 197.774814 -232.764838) (xy 197.916038 -232.906062)
				(xy 197.916038 -233.103166) (xy 197.834504 -233.1847) (xy 197.834504 -233.557064) (xy 197.736968 -233.557064)
				(xy 197.689978 -233.557064)
			)
		)
	)
	(zone
		(layer "F.Cu")
		(hatch none 0.5)
		(connect_pads
			(clearance 0)
		)
		(min_thickness 0.25)
		(keepout
			(tracks allowed)
			(vias allowed)
			(pads allowed)
			(copperpour allowed)
			(footprints allowed)
		)
		(placement
			(enabled no)
			(sheetname "")
		)
		(fill
			(thermal_gap 0.5)
			(thermal_bridge_width 0.5)
			(island_removal_mode 0)
		)
		(polygon
			(pts
				(xy 195.510658 -289.654996) (xy 195.510658 -289.426396) (xy 197.542658 -289.426396) (xy 197.542658 -289.654996)
			)
		)
	)
	(zone
		(layer "F.Cu")
		(hatch none 0.5)
		(connect_pads
			(clearance 0)
		)
		(min_thickness 0.25)
		(keepout
			(tracks allowed)
			(vias allowed)
			(pads allowed)
			(copperpour allowed)
			(footprints allowed)
		)
		(placement
			(enabled no)
			(sheetname "")
		)
		(fill
			(thermal_gap 0.5)
			(thermal_bridge_width 0.5)
			(island_removal_mode 0)
		)
		(polygon
			(pts
				(xy 63.65748 -158.582868) (xy 63.65748 -154.381708) (xy 65.60058 -154.381708) (xy 65.60058 -158.582868)
			)
		)
	)
	(zone
		(layer "F.Cu")
		(hatch none 0.5)
		(connect_pads
			(clearance 0)
		)
		(min_thickness 0.25)
		(keepout
			(tracks allowed)
			(vias allowed)
			(pads allowed)
			(copperpour allowed)
			(footprints not_allowed)
		)
		(placement
			(enabled no)
			(sheetname "")
		)
		(fill
			(thermal_gap 0.5)
			(thermal_bridge_width 0.5)
			(island_removal_mode 0)
		)
		(polygon
			(pts
				(arc
					(start 21.049996 -67.00012)
					(mid 36.049966 -52.00015)
					(end 21.049996 -36.999926)
				)
				(xy 21.049996 -37.675058) (xy 24.04999 -37.675058) (xy 24.04999 -66.324988) (xy 21.049996 -66.324988)
			)
		)
	)
	(zone
		(layer "F.Cu")
		(hatch none 0.5)
		(connect_pads
			(clearance 0)
		)
		(min_thickness 0.25)
		(keepout
			(tracks allowed)
			(vias allowed)
			(pads allowed)
			(copperpour allowed)
			(footprints allowed)
		)
		(placement
			(enabled no)
			(sheetname "")
		)
		(fill
			(thermal_gap 0.5)
			(thermal_bridge_width 0.5)
			(island_removal_mode 0)
		)
		(polygon
			(pts
				(xy 29.647642 -280.416508) (xy 29.647642 -279.97277) (xy 31.972758 -279.97277) (xy 31.972758 -280.416508)
			)
		)
	)
	(zone
		(layer "F.Cu")
		(hatch none 0.5)
		(connect_pads
			(clearance 0)
		)
		(min_thickness 0.25)
		(keepout
			(tracks allowed)
			(vias allowed)
			(pads allowed)
			(copperpour allowed)
			(footprints not_allowed)
		)
		(placement
			(enabled no)
			(sheetname "")
		)
		(fill
			(thermal_gap 0.5)
			(thermal_bridge_width 0.5)
			(island_removal_mode 0)
		)
		(polygon
			(pts
				(xy 79.680054 -210.769962) (xy 79.680054 -292.770052) (xy 144.180052 -292.770052) (xy 144.180052 -210.769962)
			)
		)
	)
	(zone
		(layer "F.Cu")
		(hatch none 0.5)
		(connect_pads
			(clearance 0)
		)
		(min_thickness 0.25)
		(keepout
			(tracks allowed)
			(vias allowed)
			(pads allowed)
			(copperpour allowed)
			(footprints allowed)
		)
		(placement
			(enabled no)
			(sheetname "")
		)
		(fill
			(thermal_gap 0.5)
			(thermal_bridge_width 0.5)
			(island_removal_mode 0)
		)
		(polygon
			(pts
				(xy 40.509698 -20.10791) (xy 40.509698 -16.973296) (xy 42.28846 -16.973296) (xy 42.28846 -20.10791)
			)
		)
	)
	(zone
		(layer "F.Cu")
		(hatch none 0.5)
		(connect_pads
			(clearance 0)
		)
		(min_thickness 0.25)
		(keepout
			(tracks allowed)
			(vias allowed)
			(pads allowed)
			(copperpour allowed)
			(footprints allowed)
		)
		(placement
			(enabled no)
			(sheetname "")
		)
		(fill
			(thermal_gap 0.5)
			(thermal_bridge_width 0.5)
			(island_removal_mode 0)
		)
		(polygon
			(pts
				(xy 161.963354 -267.554964) (xy 161.963354 -267.326364) (xy 163.842954 -267.326364) (xy 163.842954 -267.554964)
			)
		)
	)
	(zone
		(layer "F.Cu")
		(hatch none 0.5)
		(connect_pads
			(clearance 0)
		)
		(min_thickness 0.25)
		(keepout
			(tracks allowed)
			(vias allowed)
			(pads allowed)
			(copperpour allowed)
			(footprints not_allowed)
		)
		(placement
			(enabled no)
			(sheetname "")
		)
		(fill
			(thermal_gap 0.5)
			(thermal_bridge_width 0.5)
			(island_removal_mode 0)
		)
		(polygon
			(pts
				(arc
					(start 320.099944 -160.50006)
					(mid 322.90004 -157.699964)
					(end 325.699882 -160.50006)
				)
				(arc
					(start 325.699882 -160.50006)
					(mid 322.90004 -163.299902)
					(end 320.099944 -160.50006)
				)
			)
		)
	)
	(zone
		(layer "F.Cu")
		(hatch none 0.5)
		(connect_pads
			(clearance 0)
		)
		(min_thickness 0.25)
		(keepout
			(tracks allowed)
			(vias allowed)
			(pads allowed)
			(copperpour allowed)
			(footprints allowed)
		)
		(placement
			(enabled no)
			(sheetname "")
		)
		(fill
			(thermal_gap 0.5)
			(thermal_bridge_width 0.5)
			(island_removal_mode 0)
		)
		(polygon
			(pts
				(xy 14.560042 -212.416644) (xy 14.560042 -211.972906) (xy 16.885158 -211.972906) (xy 16.885158 -212.416644)
			)
		)
	)
	(zone
		(layer "F.Cu")
		(hatch none 0.5)
		(connect_pads
			(clearance 0)
		)
		(min_thickness 0.25)
		(keepout
			(tracks allowed)
			(vias allowed)
			(pads allowed)
			(copperpour allowed)
			(footprints allowed)
		)
		(placement
			(enabled no)
			(sheetname "")
		)
		(fill
			(thermal_gap 0.5)
			(thermal_bridge_width 0.5)
			(island_removal_mode 0)
		)
		(polygon
			(pts
				(xy 176.979326 -294.526208) (xy 179.011326 -294.526208) (xy 179.011326 -294.754808) (xy 176.979326 -294.754808)
				(xy 176.848008 -294.754808) (xy 176.8221 -294.754808) (xy 176.8221 -294.526208) (xy 176.848008 -294.526208)
			)
		)
	)
	(zone
		(layer "F.Cu")
		(hatch none 0.5)
		(connect_pads
			(clearance 0)
		)
		(min_thickness 0.25)
		(keepout
			(tracks allowed)
			(vias allowed)
			(pads allowed)
			(copperpour allowed)
			(footprints allowed)
		)
		(placement
			(enabled no)
			(sheetname "")
		)
		(fill
			(thermal_gap 0.5)
			(thermal_bridge_width 0.5)
			(island_removal_mode 0)
		)
		(polygon
			(pts
				(xy 384.81508 -218.493848) (xy 385.1021 -218.493848) (xy 385.13258 -218.463368) (xy 385.13258 -217.835988)
				(xy 385.04622 -217.749628) (xy 384.85826 -217.749628) (xy 384.7846 -217.823288) (xy 384.7846 -218.463368)
			)
		)
	)
	(zone
		(layer "F.Cu")
		(hatch none 0.5)
		(connect_pads
			(clearance 0)
		)
		(min_thickness 0.25)
		(keepout
			(tracks allowed)
			(vias allowed)
			(pads allowed)
			(copperpour allowed)
			(footprints allowed)
		)
		(placement
			(enabled no)
			(sheetname "")
		)
		(fill
			(thermal_gap 0.5)
			(thermal_bridge_width 0.5)
			(island_removal_mode 0)
		)
		(polygon
			(pts
				(xy 274.143978 -284.666436) (xy 274.143978 -284.222698) (xy 276.469094 -284.222698) (xy 276.469094 -284.666436)
			)
		)
	)
	(zone
		(layer "F.Cu")
		(hatch none 0.5)
		(connect_pads
			(clearance 0)
		)
		(min_thickness 0.25)
		(keepout
			(tracks allowed)
			(vias allowed)
			(pads allowed)
			(copperpour allowed)
			(footprints allowed)
		)
		(placement
			(enabled no)
			(sheetname "")
		)
		(fill
			(thermal_gap 0.5)
			(thermal_bridge_width 0.5)
			(island_removal_mode 0)
		)
		(polygon
			(pts
				(xy 157.791658 -211.455) (xy 157.791658 -211.2264) (xy 159.823658 -211.2264) (xy 159.823658 -211.455)
			)
		)
	)
	(zone
		(layer "F.Cu")
		(hatch none 0.5)
		(connect_pads
			(clearance 0)
		)
		(min_thickness 0.25)
		(keepout
			(tracks allowed)
			(vias allowed)
			(pads allowed)
			(copperpour allowed)
			(footprints allowed)
		)
		(placement
			(enabled no)
			(sheetname "")
		)
		(fill
			(thermal_gap 0.5)
			(thermal_bridge_width 0.5)
			(island_removal_mode 0)
		)
		(polygon
			(pts
				(xy 409.57373 -319.243202) (xy 409.57373 -318.252602) (xy 409.11653 -317.795402) (xy 409.11653 -317.084202)
				(xy 409.31973 -316.881002) (xy 409.57373 -316.881002) (xy 412.18993 -316.881002) (xy 412.18993 -319.243202)
			)
		)
	)
	(zone
		(layer "F.Cu")
		(hatch none 0.5)
		(connect_pads
			(clearance 0)
		)
		(min_thickness 0.25)
		(keepout
			(tracks allowed)
			(vias allowed)
			(pads allowed)
			(copperpour allowed)
			(footprints allowed)
		)
		(placement
			(enabled no)
			(sheetname "")
		)
		(fill
			(thermal_gap 0.5)
			(thermal_bridge_width 0.5)
			(island_removal_mode 0)
		)
		(polygon
			(pts
				(xy 307.76291 -208.166462) (xy 307.76291 -207.722724) (xy 310.088026 -207.722724) (xy 310.088026 -208.166462)
			)
		)
	)
	(zone
		(layer "F.Cu")
		(hatch none 0.5)
		(connect_pads
			(clearance 0)
		)
		(min_thickness 0.25)
		(keepout
			(tracks allowed)
			(vias allowed)
			(pads allowed)
			(copperpour allowed)
			(footprints allowed)
		)
		(placement
			(enabled no)
			(sheetname "")
		)
		(fill
			(thermal_gap 0.5)
			(thermal_bridge_width 0.5)
			(island_removal_mode 0)
		)
		(polygon
			(pts
				(xy 443.450726 -227.604828) (xy 443.450726 -227.376228) (xy 445.482726 -227.376228) (xy 445.482726 -227.604828)
			)
		)
	)
	(zone
		(layer "F.Cu")
		(hatch none 0.5)
		(connect_pads
			(clearance 0)
		)
		(min_thickness 0.25)
		(keepout
			(tracks allowed)
			(vias allowed)
			(pads allowed)
			(copperpour allowed)
			(footprints allowed)
		)
		(placement
			(enabled no)
			(sheetname "")
		)
		(fill
			(thermal_gap 0.5)
			(thermal_bridge_width 0.5)
			(island_removal_mode 0)
		)
		(polygon
			(pts
				(xy 157.791658 -198.704962) (xy 157.791658 -198.476362) (xy 159.823658 -198.476362) (xy 159.823658 -198.704962)
			)
		)
	)
	(zone
		(layer "F.Cu")
		(hatch none 0.5)
		(connect_pads
			(clearance 0)
		)
		(min_thickness 0.25)
		(keepout
			(tracks allowed)
			(vias allowed)
			(pads allowed)
			(copperpour allowed)
			(footprints allowed)
		)
		(placement
			(enabled no)
			(sheetname "")
		)
		(fill
			(thermal_gap 0.5)
			(thermal_bridge_width 0.5)
			(island_removal_mode 0)
		)
		(polygon
			(pts
				(xy 63.977012 -249.81662) (xy 63.977012 -249.372882) (xy 66.186812 -249.372882) (xy 66.186812 -249.81662)
			)
		)
	)
	(zone
		(layer "F.Cu")
		(hatch none 0.5)
		(connect_pads
			(clearance 0)
		)
		(min_thickness 0.25)
		(keepout
			(tracks allowed)
			(vias allowed)
			(pads allowed)
			(copperpour allowed)
			(footprints allowed)
		)
		(placement
			(enabled no)
			(sheetname "")
		)
		(fill
			(thermal_gap 0.5)
			(thermal_bridge_width 0.5)
			(island_removal_mode 0)
		)
		(polygon
			(pts
				(xy 59.822842 -308.46649) (xy 59.822842 -308.022752) (xy 62.147958 -308.022752) (xy 62.147958 -308.46649)
			)
		)
	)
	(zone
		(layer "F.Cu")
		(hatch none 0.5)
		(connect_pads
			(clearance 0)
		)
		(min_thickness 0.25)
		(keepout
			(tracks allowed)
			(vias allowed)
			(pads allowed)
			(copperpour allowed)
			(footprints allowed)
		)
		(placement
			(enabled no)
			(sheetname "")
		)
		(fill
			(thermal_gap 0.5)
			(thermal_bridge_width 0.5)
			(island_removal_mode 0)
		)
		(polygon
			(pts
				(xy 26.20391 -214.96655) (xy 26.20391 -214.522812) (xy 28.529026 -214.522812) (xy 28.529026 -214.96655)
			)
		)
	)
	(zone
		(layer "F.Cu")
		(hatch none 0.5)
		(connect_pads
			(clearance 0)
		)
		(min_thickness 0.25)
		(keepout
			(tracks allowed)
			(vias allowed)
			(pads allowed)
			(copperpour allowed)
			(footprints allowed)
		)
		(placement
			(enabled no)
			(sheetname "")
		)
		(fill
			(thermal_gap 0.5)
			(thermal_bridge_width 0.5)
			(island_removal_mode 0)
		)
		(polygon
			(pts
				(xy 14.560042 -203.06665) (xy 14.560042 -202.622912) (xy 16.885158 -202.622912) (xy 16.885158 -203.06665)
			)
		)
	)
	(zone
		(layer "F.Cu")
		(hatch none 0.5)
		(connect_pads
			(clearance 0)
		)
		(min_thickness 0.25)
		(keepout
			(tracks allowed)
			(vias allowed)
			(pads allowed)
			(copperpour allowed)
			(footprints allowed)
		)
		(placement
			(enabled no)
			(sheetname "")
		)
		(fill
			(thermal_gap 0.5)
			(thermal_bridge_width 0.5)
			(island_removal_mode 0)
		)
		(polygon
			(pts
				(xy 424.919394 -275.206968) (xy 426.951394 -275.206968) (xy 426.951394 -274.978368) (xy 424.919394 -274.978368)
				(xy 424.788076 -274.978368) (xy 424.762168 -274.978368) (xy 424.762168 -275.206968) (xy 424.788076 -275.206968)
			)
		)
	)
	(zone
		(layer "F.Cu")
		(hatch none 0.5)
		(connect_pads
			(clearance 0)
		)
		(min_thickness 0.25)
		(keepout
			(tracks not_allowed)
			(vias allowed)
			(pads allowed)
			(copperpour not_allowed)
			(footprints allowed)
		)
		(placement
			(enabled no)
			(sheetname "")
		)
		(fill
			(thermal_gap 0.5)
			(thermal_bridge_width 0.5)
			(island_removal_mode 0)
		)
		(polygon
			(pts
				(xy 119.434864 -336.26044) (xy 123.37034 -336.26044) (xy 123.37034 -336.215228) (xy 123.23064 -336.075528)
				(xy 121.822718 -336.075528) (xy 121.822718 -333.916528) (xy 123.979432 -333.916528) (xy 123.979432 -333.666846)
				(xy 121.64568 -333.666846) (xy 121.64568 -333.987648) (xy 121.53138 -333.987648) (xy 121.53138 -336.019902)
				(xy 119.67718 -336.019902) (xy 119.67718 -335.778856) (xy 119.434864 -335.778856)
			)
		)
	)
	(zone
		(layer "F.Cu")
		(hatch none 0.5)
		(connect_pads
			(clearance 0)
		)
		(min_thickness 0.25)
		(keepout
			(tracks not_allowed)
			(vias allowed)
			(pads allowed)
			(copperpour not_allowed)
			(footprints allowed)
		)
		(placement
			(enabled no)
			(sheetname "")
		)
		(fill
			(thermal_gap 0.5)
			(thermal_bridge_width 0.5)
			(island_removal_mode 0)
		)
		(polygon
			(pts
				(arc
					(start 85.914738 -353.525074)
					(mid 81.914746 -357.525066)
					(end 77.914754 -353.525074)
				)
				(arc
					(start 77.914754 -353.525074)
					(mid 81.914746 -349.525082)
					(end 85.914738 -353.525074)
				)
			)
		)
	)
	(zone
		(layer "F.Cu")
		(hatch none 0.5)
		(connect_pads
			(clearance 0)
		)
		(min_thickness 0.25)
		(keepout
			(tracks allowed)
			(vias allowed)
			(pads allowed)
			(copperpour allowed)
			(footprints allowed)
		)
		(placement
			(enabled no)
			(sheetname "")
		)
		(fill
			(thermal_gap 0.5)
			(thermal_bridge_width 0.5)
			(island_removal_mode 0)
		)
		(polygon
			(pts
				(xy 41.29151 -216.666572) (xy 41.29151 -216.222834) (xy 43.616626 -216.222834) (xy 43.616626 -216.666572)
			)
		)
	)
	(zone
		(layer "F.Cu")
		(hatch none 0.5)
		(connect_pads
			(clearance 0)
		)
		(min_thickness 0.25)
		(keepout
			(tracks allowed)
			(vias allowed)
			(pads allowed)
			(copperpour allowed)
			(footprints allowed)
		)
		(placement
			(enabled no)
			(sheetname "")
		)
		(fill
			(thermal_gap 0.5)
			(thermal_bridge_width 0.5)
			(island_removal_mode 0)
		)
		(polygon
			(pts
				(xy 385.85394 -286.606488) (xy 386.14096 -286.606488) (xy 386.17144 -286.576008) (xy 386.17144 -285.948628)
				(xy 386.08508 -285.862268) (xy 385.89712 -285.862268) (xy 385.82346 -285.935928) (xy 385.82346 -286.576008)
			)
		)
	)
	(zone
		(layer "F.Cu")
		(hatch none 0.5)
		(connect_pads
			(clearance 0)
		)
		(min_thickness 0.25)
		(keepout
			(tracks allowed)
			(vias allowed)
			(pads allowed)
			(copperpour allowed)
			(footprints allowed)
		)
		(placement
			(enabled no)
			(sheetname "")
		)
		(fill
			(thermal_gap 0.5)
			(thermal_bridge_width 0.5)
			(island_removal_mode 0)
		)
		(polygon
			(pts
				(xy 85.627972 -410.948886) (xy 85.627972 -406.105868) (xy 87.512398 -406.105868) (xy 87.512398 -410.948886)
			)
		)
	)
	(zone
		(layer "F.Cu")
		(hatch none 0.5)
		(connect_pads
			(clearance 0)
		)
		(min_thickness 0.25)
		(keepout
			(tracks allowed)
			(vias allowed)
			(pads allowed)
			(copperpour allowed)
			(footprints allowed)
		)
		(placement
			(enabled no)
			(sheetname "")
		)
		(fill
			(thermal_gap 0.5)
			(thermal_bridge_width 0.5)
			(island_removal_mode 0)
		)
		(polygon
			(pts
				(xy 121.470928 -335.958942) (xy 119.723408 -335.958942) (xy 119.723408 -334.023462) (xy 121.470928 -334.023462)
			)
		)
	)
	(zone
		(layer "F.Cu")
		(hatch none 0.5)
		(connect_pads
			(clearance 0)
		)
		(min_thickness 0.25)
		(keepout
			(tracks allowed)
			(vias allowed)
			(pads allowed)
			(copperpour allowed)
			(footprints allowed)
		)
		(placement
			(enabled no)
			(sheetname "")
		)
		(fill
			(thermal_gap 0.5)
			(thermal_bridge_width 0.5)
			(island_removal_mode 0)
		)
		(polygon
			(pts
				(xy 41.29151 -294.866568) (xy 41.29151 -294.42283) (xy 43.616626 -294.42283) (xy 43.616626 -294.866568)
			)
		)
	)
	(zone
		(layer "F.Cu")
		(hatch none 0.5)
		(connect_pads
			(clearance 0)
		)
		(min_thickness 0.25)
		(keepout
			(tracks allowed)
			(vias allowed)
			(pads allowed)
			(copperpour allowed)
			(footprints allowed)
		)
		(placement
			(enabled no)
			(sheetname "")
		)
		(fill
			(thermal_gap 0.5)
			(thermal_bridge_width 0.5)
			(island_removal_mode 0)
		)
		(polygon
			(pts
				(xy 44.735242 -301.666656) (xy 44.735242 -301.222918) (xy 47.060358 -301.222918) (xy 47.060358 -301.666656)
			)
		)
	)
	(zone
		(layer "F.Cu")
		(hatch none 0.5)
		(connect_pads
			(clearance 0)
		)
		(min_thickness 0.25)
		(keepout
			(tracks allowed)
			(vias allowed)
			(pads allowed)
			(copperpour allowed)
			(footprints allowed)
		)
		(placement
			(enabled no)
			(sheetname "")
		)
		(fill
			(thermal_gap 0.5)
			(thermal_bridge_width 0.5)
			(island_removal_mode 0)
		)
		(polygon
			(pts
				(xy 262.50011 -230.266494) (xy 262.50011 -229.822756) (xy 264.825226 -229.822756) (xy 264.825226 -230.266494)
			)
		)
	)
	(zone
		(layer "F.Cu")
		(hatch none 0.5)
		(connect_pads
			(clearance 0)
		)
		(min_thickness 0.25)
		(keepout
			(tracks allowed)
			(vias allowed)
			(pads allowed)
			(copperpour allowed)
			(footprints allowed)
		)
		(placement
			(enabled no)
			(sheetname "")
		)
		(fill
			(thermal_gap 0.5)
			(thermal_bridge_width 0.5)
			(island_removal_mode 0)
		)
		(polygon
			(pts
				(xy 94.7547 -321.366388) (xy 94.7547 -319.080388) (xy 99.14128 -319.080388) (xy 99.14128 -321.366388)
			)
		)
	)
	(zone
		(layer "F.Cu")
		(hatch none 0.5)
		(connect_pads
			(clearance 0)
		)
		(min_thickness 0.25)
		(keepout
			(tracks allowed)
			(vias allowed)
			(pads allowed)
			(copperpour allowed)
			(footprints allowed)
		)
		(placement
			(enabled no)
			(sheetname "")
		)
		(fill
			(thermal_gap 0.5)
			(thermal_bridge_width 0.5)
			(island_removal_mode 0)
		)
		(polygon
			(pts
				(xy 311.94248 -266.816586) (xy 311.94248 -266.372848) (xy 314.12688 -266.372848) (xy 314.12688 -266.816586)
			)
		)
	)
	(zone
		(layer "F.Cu")
		(hatch none 0.5)
		(connect_pads
			(clearance 0)
		)
		(min_thickness 0.25)
		(keepout
			(tracks not_allowed)
			(vias allowed)
			(pads allowed)
			(copperpour not_allowed)
			(footprints allowed)
		)
		(placement
			(enabled no)
			(sheetname "")
		)
		(fill
			(thermal_gap 0.5)
			(thermal_bridge_width 0.5)
			(island_removal_mode 0)
		)
		(polygon
			(pts
				(arc
					(start 132.518912 -354.434902)
					(mid 136.518904 -350.43491)
					(end 140.518896 -354.434902)
				)
				(arc
					(start 140.518896 -354.434902)
					(mid 136.518904 -358.434894)
					(end 132.518912 -354.434902)
				)
			)
		)
	)
	(zone
		(layer "F.Cu")
		(hatch none 0.5)
		(connect_pads
			(clearance 0)
		)
		(min_thickness 0.25)
		(keepout
			(tracks allowed)
			(vias allowed)
			(pads allowed)
			(copperpour allowed)
			(footprints allowed)
		)
		(placement
			(enabled no)
			(sheetname "")
		)
		(fill
			(thermal_gap 0.5)
			(thermal_bridge_width 0.5)
			(island_removal_mode 0)
		)
		(polygon
			(pts
				(xy 277.58771 -220.9165) (xy 277.58771 -220.472762) (xy 279.912826 -220.472762) (xy 279.912826 -220.9165)
			)
		)
	)
	(zone
		(layer "F.Cu")
		(hatch none 0.5)
		(connect_pads
			(clearance 0)
		)
		(min_thickness 0.25)
		(keepout
			(tracks allowed)
			(vias allowed)
			(pads allowed)
			(copperpour allowed)
			(footprints allowed)
		)
		(placement
			(enabled no)
			(sheetname "")
		)
		(fill
			(thermal_gap 0.5)
			(thermal_bridge_width 0.5)
			(island_removal_mode 0)
		)
		(polygon
			(pts
				(xy 207.154526 -205.27645) (xy 209.186526 -205.27645) (xy 209.186526 -205.50505) (xy 207.154526 -205.50505)
				(xy 207.018382 -205.50505) (xy 206.971392 -205.50505) (xy 206.971392 -205.27645) (xy 207.018382 -205.27645)
			)
		)
	)
	(zone
		(layer "F.Cu")
		(hatch none 0.5)
		(connect_pads
			(clearance 0)
		)
		(min_thickness 0.25)
		(keepout
			(tracks allowed)
			(vias allowed)
			(pads allowed)
			(copperpour allowed)
			(footprints allowed)
		)
		(placement
			(enabled no)
			(sheetname "")
		)
		(fill
			(thermal_gap 0.5)
			(thermal_bridge_width 0.5)
			(island_removal_mode 0)
		)
		(polygon
			(pts
				(xy 165.335458 -289.654996) (xy 165.335458 -289.426396) (xy 167.367458 -289.426396) (xy 167.367458 -289.654996)
			)
		)
	)
	(zone
		(layer "F.Cu")
		(hatch none 0.5)
		(connect_pads
			(clearance 0)
		)
		(min_thickness 0.25)
		(keepout
			(tracks allowed)
			(vias allowed)
			(pads allowed)
			(copperpour allowed)
			(footprints allowed)
		)
		(placement
			(enabled no)
			(sheetname "")
		)
		(fill
			(thermal_gap 0.5)
			(thermal_bridge_width 0.5)
			(island_removal_mode 0)
		)
		(polygon
			(pts
				(xy 292.67531 -290.61664) (xy 292.67531 -290.172902) (xy 295.000426 -290.172902) (xy 295.000426 -290.61664)
			)
		)
	)
	(zone
		(layer "F.Cu")
		(hatch none 0.5)
		(connect_pads
			(clearance 0)
		)
		(min_thickness 0.25)
		(keepout
			(tracks not_allowed)
			(vias allowed)
			(pads allowed)
			(copperpour not_allowed)
			(footprints allowed)
		)
		(placement
			(enabled no)
			(sheetname "")
		)
		(fill
			(thermal_gap 0.5)
			(thermal_bridge_width 0.5)
			(island_removal_mode 0)
		)
		(polygon
			(pts
				(arc
					(start 201.399902 -22.29993)
					(mid 203.399898 -20.299934)
					(end 205.399894 -22.29993)
				)
				(arc
					(start 205.399894 -22.29993)
					(mid 203.399898 -24.299926)
					(end 201.399902 -22.29993)
				)
			)
		)
	)
	(zone
		(layer "F.Cu")
		(hatch none 0.5)
		(connect_pads
			(clearance 0)
		)
		(min_thickness 0.25)
		(keepout
			(tracks allowed)
			(vias allowed)
			(pads allowed)
			(copperpour allowed)
			(footprints allowed)
		)
		(placement
			(enabled no)
			(sheetname "")
		)
		(fill
			(thermal_gap 0.5)
			(thermal_bridge_width 0.5)
			(island_removal_mode 0)
		)
		(polygon
			(pts
				(xy 176.979326 -297.076368) (xy 179.011326 -297.076368) (xy 179.011326 -297.304968) (xy 176.979326 -297.304968)
				(xy 176.843182 -297.304968) (xy 176.796192 -297.304968) (xy 176.796192 -297.076368) (xy 176.843182 -297.076368)
			)
		)
	)
	(zone
		(layer "F.Cu")
		(hatch none 0.5)
		(connect_pads
			(clearance 0)
		)
		(min_thickness 0.25)
		(keepout
			(tracks allowed)
			(vias allowed)
			(pads allowed)
			(copperpour allowed)
			(footprints allowed)
		)
		(placement
			(enabled no)
			(sheetname "")
		)
		(fill
			(thermal_gap 0.5)
			(thermal_bridge_width 0.5)
			(island_removal_mode 0)
		)
		(polygon
			(pts
				(xy 165.335458 -199.554846) (xy 165.335458 -199.326246) (xy 167.367458 -199.326246) (xy 167.367458 -199.554846)
			)
		)
	)
	(zone
		(layer "F.Cu")
		(hatch none 0.5)
		(connect_pads
			(clearance 0)
		)
		(min_thickness 0.25)
		(keepout
			(tracks allowed)
			(vias allowed)
			(pads allowed)
			(copperpour allowed)
			(footprints allowed)
		)
		(placement
			(enabled no)
			(sheetname "")
		)
		(fill
			(thermal_gap 0.5)
			(thermal_bridge_width 0.5)
			(island_removal_mode 0)
		)
		(polygon
			(pts
				(xy 440.006994 -285.176214) (xy 442.038994 -285.176214) (xy 442.038994 -285.404814) (xy 440.006994 -285.404814)
				(xy 439.875676 -285.404814) (xy 439.849768 -285.404814) (xy 439.849768 -285.176214) (xy 439.875676 -285.176214)
			)
		)
	)
	(zone
		(layer "F.Cu")
		(hatch none 0.5)
		(connect_pads
			(clearance 0)
		)
		(min_thickness 0.25)
		(keepout
			(tracks allowed)
			(vias allowed)
			(pads allowed)
			(copperpour allowed)
			(footprints allowed)
		)
		(placement
			(enabled no)
			(sheetname "")
		)
		(fill
			(thermal_gap 0.5)
			(thermal_bridge_width 0.5)
			(island_removal_mode 0)
		)
		(polygon
			(pts
				(xy 10.96264 -107.41406) (xy 10.96264 -104.37114) (xy 13.25626 -104.37114) (xy 13.25626 -107.41406)
			)
		)
	)
	(zone
		(layer "F.Cu")
		(hatch none 0.5)
		(connect_pads
			(clearance 0)
		)
		(min_thickness 0.25)
		(keepout
			(tracks allowed)
			(vias allowed)
			(pads allowed)
			(copperpour allowed)
			(footprints allowed)
		)
		(placement
			(enabled no)
			(sheetname "")
		)
		(fill
			(thermal_gap 0.5)
			(thermal_bridge_width 0.5)
			(island_removal_mode 0)
		)
		(polygon
			(pts
				(xy 443.450726 -310.90489) (xy 443.450726 -310.67629) (xy 445.482726 -310.67629) (xy 445.482726 -310.90489)
			)
		)
	)
	(zone
		(layer "F.Cu")
		(hatch none 0.5)
		(connect_pads
			(clearance 0)
		)
		(min_thickness 0.25)
		(keepout
			(tracks allowed)
			(vias allowed)
			(pads allowed)
			(copperpour allowed)
			(footprints allowed)
		)
		(placement
			(enabled no)
			(sheetname "")
		)
		(fill
			(thermal_gap 0.5)
			(thermal_bridge_width 0.5)
			(island_removal_mode 0)
		)
		(polygon
			(pts
				(xy 161.891726 -203.805028) (xy 161.891726 -203.576428) (xy 163.923726 -203.576428) (xy 163.923726 -203.805028)
			)
		)
	)
	(zone
		(layer "F.Cu")
		(hatch none 0.5)
		(connect_pads
			(clearance 0)
		)
		(min_thickness 0.25)
		(keepout
			(tracks allowed)
			(vias allowed)
			(pads allowed)
			(copperpour allowed)
			(footprints allowed)
		)
		(placement
			(enabled no)
			(sheetname "")
		)
		(fill
			(thermal_gap 0.5)
			(thermal_bridge_width 0.5)
			(island_removal_mode 0)
		)
		(polygon
			(pts
				(xy 440.006994 -314.076334) (xy 442.038994 -314.076334) (xy 442.038994 -314.304934) (xy 440.006994 -314.304934)
				(xy 439.87085 -314.304934) (xy 439.82386 -314.304934) (xy 439.82386 -314.076334) (xy 439.87085 -314.076334)
			)
		)
	)
	(zone
		(layer "F.Cu")
		(hatch none 0.5)
		(connect_pads
			(clearance 0)
		)
		(min_thickness 0.25)
		(keepout
			(tracks not_allowed)
			(vias allowed)
			(pads allowed)
			(copperpour not_allowed)
			(footprints allowed)
		)
		(placement
			(enabled no)
			(sheetname "")
		)
		(fill
			(thermal_gap 0.5)
			(thermal_bridge_width 0.5)
			(island_removal_mode 0)
		)
		(polygon
			(pts
				(xy 233.8959 -252.113288) (xy 233.8959 -251.899928) (xy 234.91952 -251.899928) (xy 234.91952 -252.113288)
			)
		)
	)
	(zone
		(layer "F.Cu")
		(hatch none 0.5)
		(connect_pads
			(clearance 0)
		)
		(min_thickness 0.25)
		(keepout
			(tracks allowed)
			(vias allowed)
			(pads allowed)
			(copperpour allowed)
			(footprints allowed)
		)
		(placement
			(enabled no)
			(sheetname "")
		)
		(fill
			(thermal_gap 0.5)
			(thermal_bridge_width 0.5)
			(island_removal_mode 0)
		)
		(polygon
			(pts
				(xy 428.363126 -203.805028) (xy 428.363126 -203.576428) (xy 430.395126 -203.576428) (xy 430.395126 -203.805028)
			)
		)
	)
	(zone
		(layer "F.Cu")
		(hatch none 0.5)
		(connect_pads
			(clearance 0)
		)
		(min_thickness 0.25)
		(keepout
			(tracks allowed)
			(vias allowed)
			(pads allowed)
			(copperpour allowed)
			(footprints allowed)
		)
		(placement
			(enabled no)
			(sheetname "")
		)
		(fill
			(thermal_gap 0.5)
			(thermal_bridge_width 0.5)
			(island_removal_mode 0)
		)
		(polygon
			(pts
				(xy 59.822842 -271.472914) (xy 62.147958 -271.472914) (xy 62.209172 -271.472914) (xy 62.209172 -272.39849)
				(xy 59.688476 -272.39849) (xy 59.688476 -271.472914)
			)
		)
	)
	(zone
		(layer "F.Cu")
		(hatch none 0.5)
		(connect_pads
			(clearance 0)
		)
		(min_thickness 0.25)
		(keepout
			(tracks allowed)
			(vias allowed)
			(pads allowed)
			(copperpour allowed)
			(footprints allowed)
		)
		(placement
			(enabled no)
			(sheetname "")
		)
		(fill
			(thermal_gap 0.5)
			(thermal_bridge_width 0.5)
			(island_removal_mode 0)
		)
		(polygon
			(pts
				(xy 334.54086 -324.683628) (xy 334.54086 -322.433188) (xy 338.97316 -322.433188) (xy 338.97316 -324.683628)
			)
		)
	)
	(zone
		(layer "F.Cu")
		(hatch none 0.5)
		(connect_pads
			(clearance 0)
		)
		(min_thickness 0.25)
		(keepout
			(tracks not_allowed)
			(vias allowed)
			(pads allowed)
			(copperpour not_allowed)
			(footprints allowed)
		)
		(placement
			(enabled no)
			(sheetname "")
		)
		(fill
			(thermal_gap 0.5)
			(thermal_bridge_width 0.5)
			(island_removal_mode 0)
		)
		(polygon
			(pts
				(xy 179.66817 -355.161088) (xy 179.910486 -355.161088) (xy 179.910486 -354.327968) (xy 179.66817 -354.327968)
			)
		)
	)
	(zone
		(layer "F.Cu")
		(hatch none 0.5)
		(connect_pads
			(clearance 0)
		)
		(min_thickness 0.25)
		(keepout
			(tracks allowed)
			(vias allowed)
			(pads allowed)
			(copperpour allowed)
			(footprints allowed)
		)
		(placement
			(enabled no)
			(sheetname "")
		)
		(fill
			(thermal_gap 0.5)
			(thermal_bridge_width 0.5)
			(island_removal_mode 0)
		)
		(polygon
			(pts
				(xy 59.822842 -226.86645) (xy 59.822842 -226.422712) (xy 62.147958 -226.422712) (xy 62.147958 -226.86645)
			)
		)
	)
	(zone
		(layer "F.Cu")
		(hatch none 0.5)
		(connect_pads
			(clearance 0)
		)
		(min_thickness 0.25)
		(keepout
			(tracks allowed)
			(vias allowed)
			(pads allowed)
			(copperpour allowed)
			(footprints allowed)
		)
		(placement
			(enabled no)
			(sheetname "")
		)
		(fill
			(thermal_gap 0.5)
			(thermal_bridge_width 0.5)
			(island_removal_mode 0)
		)
		(polygon
			(pts
				(xy 424.964098 -361.279948) (xy 423.147998 -361.279948) (xy 423.147998 -359.900728) (xy 424.964098 -359.900728)
			)
		)
	)
	(zone
		(layer "F.Cu")
		(hatch none 0.5)
		(connect_pads
			(clearance 0)
		)
		(min_thickness 0.25)
		(keepout
			(tracks allowed)
			(vias allowed)
			(pads allowed)
			(copperpour allowed)
			(footprints allowed)
		)
		(placement
			(enabled no)
			(sheetname "")
		)
		(fill
			(thermal_gap 0.5)
			(thermal_bridge_width 0.5)
			(island_removal_mode 0)
		)
		(polygon
			(pts
				(xy 405.731726 -286.254952) (xy 405.731726 -286.026352) (xy 407.763726 -286.026352) (xy 407.763726 -286.254952)
			)
		)
	)
	(zone
		(layer "F.Cu")
		(hatch none 0.5)
		(connect_pads
			(clearance 0)
		)
		(min_thickness 0.25)
		(keepout
			(tracks allowed)
			(vias allowed)
			(pads allowed)
			(copperpour allowed)
			(footprints allowed)
		)
		(placement
			(enabled no)
			(sheetname "")
		)
		(fill
			(thermal_gap 0.5)
			(thermal_bridge_width 0.5)
			(island_removal_mode 0)
		)
		(polygon
			(pts
				(xy 292.67531 -262.566658) (xy 292.67531 -262.12292) (xy 295.000426 -262.12292) (xy 295.000426 -262.566658)
			)
		)
	)
	(zone
		(layer "F.Cu")
		(hatch none 0.5)
		(connect_pads
			(clearance 0)
		)
		(min_thickness 0.25)
		(keepout
			(tracks allowed)
			(vias allowed)
			(pads allowed)
			(copperpour allowed)
			(footprints allowed)
		)
		(placement
			(enabled no)
			(sheetname "")
		)
		(fill
			(thermal_gap 0.5)
			(thermal_bridge_width 0.5)
			(island_removal_mode 0)
		)
		(polygon
			(pts
				(xy 455.094594 -201.026268) (xy 457.126594 -201.026268) (xy 457.126594 -201.254868) (xy 455.094594 -201.254868)
				(xy 454.963276 -201.254868) (xy 454.937368 -201.254868) (xy 454.937368 -201.026268) (xy 454.963276 -201.026268)
			)
		)
	)
	(zone
		(layer "F.Cu")
		(hatch none 0.5)
		(connect_pads
			(clearance 0)
		)
		(min_thickness 0.25)
		(keepout
			(tracks allowed)
			(vias allowed)
			(pads allowed)
			(copperpour allowed)
			(footprints allowed)
		)
		(placement
			(enabled no)
			(sheetname "")
		)
		(fill
			(thermal_gap 0.5)
			(thermal_bridge_width 0.5)
			(island_removal_mode 0)
		)
		(polygon
			(pts
				(xy 15.16126 -22.55012) (xy 15.16126 -20.84324) (xy 16.9926 -20.84324) (xy 16.9926 -22.55012)
			)
		)
	)
	(zone
		(layer "F.Cu")
		(hatch none 0.5)
		(connect_pads
			(clearance 0)
		)
		(min_thickness 0.25)
		(keepout
			(tracks allowed)
			(vias allowed)
			(pads allowed)
			(copperpour allowed)
			(footprints allowed)
		)
		(placement
			(enabled no)
			(sheetname "")
		)
		(fill
			(thermal_gap 0.5)
			(thermal_bridge_width 0.5)
			(island_removal_mode 0)
		)
		(polygon
			(pts
				(xy 210.598258 -274.354798) (xy 210.598258 -274.126198) (xy 212.630258 -274.126198) (xy 212.630258 -274.354798)
			)
		)
	)
	(zone
		(layer "F.Cu")
		(hatch none 0.5)
		(connect_pads
			(clearance 0)
		)
		(min_thickness 0.25)
		(keepout
			(tracks allowed)
			(vias allowed)
			(pads allowed)
			(copperpour allowed)
			(footprints allowed)
		)
		(placement
			(enabled no)
			(sheetname "")
		)
		(fill
			(thermal_gap 0.5)
			(thermal_bridge_width 0.5)
			(island_removal_mode 0)
		)
		(polygon
			(pts
				(xy 11.11631 -304.216562) (xy 11.11631 -303.772824) (xy 13.441426 -303.772824) (xy 13.441426 -304.216562)
			)
		)
	)
	(zone
		(layer "F.Cu")
		(hatch none 0.5)
		(connect_pads
			(clearance 0)
		)
		(min_thickness 0.25)
		(keepout
			(tracks allowed)
			(vias allowed)
			(pads allowed)
			(copperpour allowed)
			(footprints allowed)
		)
		(placement
			(enabled no)
			(sheetname "")
		)
		(fill
			(thermal_gap 0.5)
			(thermal_bridge_width 0.5)
			(island_removal_mode 0)
		)
		(polygon
			(pts
				(xy 88.48852 -216.019888) (xy 88.77554 -216.019888) (xy 88.80602 -215.989408) (xy 88.80602 -215.362028)
				(xy 88.71966 -215.275668) (xy 88.5317 -215.275668) (xy 88.45804 -215.349328) (xy 88.45804 -215.989408)
			)
		)
	)
	(zone
		(layer "F.Cu")
		(hatch none 0.5)
		(connect_pads
			(clearance 0)
		)
		(min_thickness 0.25)
		(keepout
			(tracks not_allowed)
			(vias allowed)
			(pads allowed)
			(copperpour not_allowed)
			(footprints allowed)
		)
		(placement
			(enabled no)
			(sheetname "")
		)
		(fill
			(thermal_gap 0.5)
			(thermal_bridge_width 0.5)
			(island_removal_mode 0)
		)
		(polygon
			(pts
				(xy 49.208944 -356.092252) (xy 53.1241 -356.092252) (xy 53.1241 -356.08006) (xy 52.95138 -355.90734)
				(xy 51.596798 -355.90734) (xy 51.596798 -353.74834) (xy 53.753512 -353.74834) (xy 53.753512 -353.498658)
				(xy 51.4477 -353.498658) (xy 51.4477 -353.814888) (xy 51.30546 -353.814888) (xy 51.30546 -355.851714)
				(xy 49.45126 -355.851714) (xy 49.45126 -355.610668) (xy 49.208944 -355.610668)
			)
		)
	)
	(zone
		(layer "F.Cu")
		(hatch none 0.5)
		(connect_pads
			(clearance 0)
		)
		(min_thickness 0.25)
		(keepout
			(tracks allowed)
			(vias allowed)
			(pads allowed)
			(copperpour allowed)
			(footprints allowed)
		)
		(placement
			(enabled no)
			(sheetname "")
		)
		(fill
			(thermal_gap 0.5)
			(thermal_bridge_width 0.5)
			(island_removal_mode 0)
		)
		(polygon
			(pts
				(xy 274.143978 -213.266528) (xy 274.143978 -212.82279) (xy 276.469094 -212.82279) (xy 276.469094 -213.266528)
			)
		)
	)
	(zone
		(layer "F.Cu")
		(hatch none 0.5)
		(connect_pads
			(clearance 0)
		)
		(min_thickness 0.25)
		(keepout
			(tracks allowed)
			(vias allowed)
			(pads allowed)
			(copperpour allowed)
			(footprints not_allowed)
		)
		(placement
			(enabled no)
			(sheetname "")
		)
		(fill
			(thermal_gap 0.5)
			(thermal_bridge_width 0.5)
			(island_removal_mode 0)
		)
		(polygon
			(pts
				(xy 467.300818 -82.763614) (xy 437.302148 -82.763614) (xy 437.30164 -87.307166) (xy 416.301682 -87.30488)
				(xy 416.30219 -82.763614) (xy 303.502314 -82.763614) (xy 303.501806 -87.293196) (xy 282.501848 -87.29091)
				(xy 282.502102 -82.763614) (xy 250.001024 -82.763614) (xy 250.001024 -91.764358) (xy 467.300056 -91.764358)
				(xy 467.300056 -82.828384)
			)
		)
	)
	(zone
		(layer "F.Cu")
		(hatch none 0.5)
		(connect_pads
			(clearance 0)
		)
		(min_thickness 0.25)
		(keepout
			(tracks allowed)
			(vias allowed)
			(pads allowed)
			(copperpour allowed)
			(footprints allowed)
		)
		(placement
			(enabled no)
			(sheetname "")
		)
		(fill
			(thermal_gap 0.5)
			(thermal_bridge_width 0.5)
			(island_removal_mode 0)
		)
		(polygon
			(pts
				(xy 63.977012 -281.266646) (xy 63.977012 -280.822908) (xy 66.212212 -280.822908) (xy 66.212212 -281.266646)
			)
		)
	)
	(zone
		(layer "F.Cu")
		(hatch none 0.5)
		(connect_pads
			(clearance 0)
		)
		(min_thickness 0.25)
		(keepout
			(tracks allowed)
			(vias allowed)
			(pads allowed)
			(copperpour allowed)
			(footprints allowed)
		)
		(placement
			(enabled no)
			(sheetname "")
		)
		(fill
			(thermal_gap 0.5)
			(thermal_bridge_width 0.5)
			(island_removal_mode 0)
		)
		(polygon
			(pts
				(xy 387.300724 -230.278432) (xy 387.50367 -230.075486) (xy 387.50367 -230.03256) (xy 387.060186 -229.588822)
				(xy 386.938012 -229.588822) (xy 386.804916 -229.721664) (xy 386.804916 -229.825804) (xy 387.257544 -230.278432)
			)
		)
	)
	(zone
		(layer "F.Cu")
		(hatch none 0.5)
		(connect_pads
			(clearance 0)
		)
		(min_thickness 0.25)
		(keepout
			(tracks allowed)
			(vias allowed)
			(pads allowed)
			(copperpour allowed)
			(footprints allowed)
		)
		(placement
			(enabled no)
			(sheetname "")
		)
		(fill
			(thermal_gap 0.5)
			(thermal_bridge_width 0.5)
			(island_removal_mode 0)
		)
		(polygon
			(pts
				(xy 259.17652 -72.875648) (xy 259.17652 -75.778868) (xy 259.65658 -76.258928) (xy 264.57656 -76.258928)
				(xy 264.57656 -74.478388) (xy 262.50646 -72.408288) (xy 259.64388 -72.408288)
			)
		)
	)
	(zone
		(layer "F.Cu")
		(hatch none 0.5)
		(connect_pads
			(clearance 0)
		)
		(min_thickness 0.25)
		(keepout
			(tracks allowed)
			(vias allowed)
			(pads allowed)
			(copperpour allowed)
			(footprints allowed)
		)
		(placement
			(enabled no)
			(sheetname "")
		)
		(fill
			(thermal_gap 0.5)
			(thermal_bridge_width 0.5)
			(island_removal_mode 0)
		)
		(polygon
			(pts
				(xy 274.143978 -312.716418) (xy 274.143978 -312.27268) (xy 276.469094 -312.27268) (xy 276.469094 -312.716418)
			)
		)
	)
	(zone
		(layer "F.Cu")
		(hatch none 0.5)
		(connect_pads
			(clearance 0)
		)
		(min_thickness 0.25)
		(keepout
			(tracks allowed)
			(vias allowed)
			(pads allowed)
			(copperpour allowed)
			(footprints allowed)
		)
		(placement
			(enabled no)
			(sheetname "")
		)
		(fill
			(thermal_gap 0.5)
			(thermal_bridge_width 0.5)
			(island_removal_mode 0)
		)
		(polygon
			(pts
				(xy 41.29151 -260.866636) (xy 41.29151 -260.422898) (xy 43.616626 -260.422898) (xy 43.616626 -260.866636)
			)
		)
	)
	(zone
		(layer "F.Cu")
		(hatch none 0.5)
		(connect_pads
			(clearance 0)
		)
		(min_thickness 0.25)
		(keepout
			(tracks allowed)
			(vias allowed)
			(pads allowed)
			(copperpour allowed)
			(footprints allowed)
		)
		(placement
			(enabled no)
			(sheetname "")
		)
		(fill
			(thermal_gap 0.5)
			(thermal_bridge_width 0.5)
			(island_removal_mode 0)
		)
		(polygon
			(pts
				(xy 458.538326 -267.554964) (xy 458.538326 -267.326364) (xy 460.570326 -267.326364) (xy 460.570326 -267.554964)
			)
		)
	)
	(zone
		(layer "F.Cu")
		(hatch none 0.5)
		(connect_pads
			(clearance 0)
		)
		(min_thickness 0.25)
		(keepout
			(tracks allowed)
			(vias allowed)
			(pads allowed)
			(copperpour allowed)
			(footprints allowed)
		)
		(placement
			(enabled no)
			(sheetname "")
		)
		(fill
			(thermal_gap 0.5)
			(thermal_bridge_width 0.5)
			(island_removal_mode 0)
		)
		(polygon
			(pts
				(xy 386.31876 -285.763208) (xy 386.60578 -285.763208) (xy 386.63626 -285.732728) (xy 386.63626 -285.105348)
				(xy 386.5499 -285.018988) (xy 386.36194 -285.018988) (xy 386.28828 -285.092648) (xy 386.28828 -285.732728)
			)
		)
	)
	(zone
		(layer "F.Cu")
		(hatch none 0.5)
		(connect_pads
			(clearance 0)
		)
		(min_thickness 0.25)
		(keepout
			(tracks allowed)
			(vias allowed)
			(pads allowed)
			(copperpour allowed)
			(footprints allowed)
		)
		(placement
			(enabled no)
			(sheetname "")
		)
		(fill
			(thermal_gap 0.5)
			(thermal_bridge_width 0.5)
			(island_removal_mode 0)
		)
		(polygon
			(pts
				(xy 333.25816 -283.345128) (xy 333.54518 -283.345128) (xy 333.57566 -283.314648) (xy 333.57566 -282.687268)
				(xy 333.4893 -282.600908) (xy 333.30134 -282.600908) (xy 333.22768 -282.674568) (xy 333.22768 -283.314648)
			)
		)
	)
	(zone
		(layer "F.Cu")
		(hatch none 0.5)
		(connect_pads
			(clearance 0)
		)
		(min_thickness 0.25)
		(keepout
			(tracks allowed)
			(vias allowed)
			(pads allowed)
			(copperpour allowed)
			(footprints allowed)
		)
		(placement
			(enabled no)
			(sheetname "")
		)
		(fill
			(thermal_gap 0.5)
			(thermal_bridge_width 0.5)
			(island_removal_mode 0)
		)
		(polygon
			(pts
				(xy 11.11631 -202.216512) (xy 11.11631 -201.772774) (xy 13.441426 -201.772774) (xy 13.441426 -202.216512)
			)
		)
	)
	(zone
		(layer "F.Cu")
		(hatch none 0.5)
		(connect_pads
			(clearance 0)
		)
		(min_thickness 0.25)
		(keepout
			(tracks allowed)
			(vias allowed)
			(pads allowed)
			(copperpour allowed)
			(footprints allowed)
		)
		(placement
			(enabled no)
			(sheetname "")
		)
		(fill
			(thermal_gap 0.5)
			(thermal_bridge_width 0.5)
			(island_removal_mode 0)
		)
		(polygon
			(pts
				(xy 311.89168 -284.666436) (xy 311.89168 -284.222698) (xy 314.17768 -284.222698) (xy 314.17768 -284.666436)
			)
		)
	)
	(zone
		(layer "F.Cu")
		(hatch none 0.5)
		(connect_pads
			(clearance 0)
		)
		(min_thickness 0.25)
		(keepout
			(tracks allowed)
			(vias allowed)
			(pads allowed)
			(copperpour allowed)
			(footprints allowed)
		)
		(placement
			(enabled no)
			(sheetname "")
		)
		(fill
			(thermal_gap 0.5)
			(thermal_bridge_width 0.5)
			(island_removal_mode 0)
		)
		(polygon
			(pts
				(xy 166.992808 -410.948886) (xy 166.992808 -406.105868) (xy 168.877234 -406.105868) (xy 168.877234 -410.948886)
			)
		)
	)
	(zone
		(layer "F.Cu")
		(hatch none 0.5)
		(connect_pads
			(clearance 0)
		)
		(min_thickness 0.25)
		(keepout
			(tracks allowed)
			(vias allowed)
			(pads allowed)
			(copperpour allowed)
			(footprints allowed)
		)
		(placement
			(enabled no)
			(sheetname "")
		)
		(fill
			(thermal_gap 0.5)
			(thermal_bridge_width 0.5)
			(island_removal_mode 0)
		)
		(polygon
			(pts
				(xy 26.20391 -233.2228) (xy 28.529026 -233.2228) (xy 28.590494 -233.2228) (xy 28.590494 -234.14609)
				(xy 26.065734 -234.14609) (xy 26.065734 -233.2228)
			)
		)
	)
	(zone
		(layer "F.Cu")
		(hatch none 0.5)
		(connect_pads
			(clearance 0)
		)
		(min_thickness 0.25)
		(keepout
			(tracks allowed)
			(vias allowed)
			(pads allowed)
			(copperpour allowed)
			(footprints allowed)
		)
		(placement
			(enabled no)
			(sheetname "")
		)
		(fill
			(thermal_gap 0.5)
			(thermal_bridge_width 0.5)
			(island_removal_mode 0)
		)
		(polygon
			(pts
				(xy 458.538326 -250.554998) (xy 458.538326 -250.326398) (xy 460.570326 -250.326398) (xy 460.570326 -250.554998)
			)
		)
	)
	(zone
		(layer "F.Cu")
		(hatch none 0.5)
		(connect_pads
			(clearance 0)
		)
		(min_thickness 0.25)
		(keepout
			(tracks allowed)
			(vias allowed)
			(pads allowed)
			(copperpour allowed)
			(footprints allowed)
		)
		(placement
			(enabled no)
			(sheetname "")
		)
		(fill
			(thermal_gap 0.5)
			(thermal_bridge_width 0.5)
			(island_removal_mode 0)
		)
		(polygon
			(pts
				(xy 259.056378 -286.366458) (xy 259.056378 -285.92272) (xy 261.381494 -285.92272) (xy 261.381494 -286.366458)
			)
		)
	)
	(zone
		(layer "F.Cu")
		(hatch none 0.5)
		(connect_pads
			(clearance 0)
		)
		(min_thickness 0.25)
		(keepout
			(tracks allowed)
			(vias allowed)
			(pads allowed)
			(copperpour allowed)
			(footprints allowed)
		)
		(placement
			(enabled no)
			(sheetname "")
		)
		(fill
			(thermal_gap 0.5)
			(thermal_bridge_width 0.5)
			(island_removal_mode 0)
		)
		(polygon
			(pts
				(xy 458.538326 -245.454932) (xy 458.538326 -245.226332) (xy 460.570326 -245.226332) (xy 460.570326 -245.454932)
			)
		)
	)
	(zone
		(layer "F.Cu")
		(hatch none 0.5)
		(connect_pads
			(clearance 0)
		)
		(min_thickness 0.25)
		(keepout
			(tracks allowed)
			(vias allowed)
			(pads allowed)
			(copperpour allowed)
			(footprints allowed)
		)
		(placement
			(enabled no)
			(sheetname "")
		)
		(fill
			(thermal_gap 0.5)
			(thermal_bridge_width 0.5)
			(island_removal_mode 0)
		)
		(polygon
			(pts
				(xy 14.560042 -224.316544) (xy 14.560042 -223.872806) (xy 16.885158 -223.872806) (xy 16.885158 -224.316544)
			)
		)
	)
	(zone
		(layer "F.Cu")
		(hatch none 0.5)
		(connect_pads
			(clearance 0)
		)
		(min_thickness 0.25)
		(keepout
			(tracks allowed)
			(vias allowed)
			(pads allowed)
			(copperpour allowed)
			(footprints allowed)
		)
		(placement
			(enabled no)
			(sheetname "")
		)
		(fill
			(thermal_gap 0.5)
			(thermal_bridge_width 0.5)
			(island_removal_mode 0)
		)
		(polygon
			(pts
				(xy 195.510658 -311.755028) (xy 195.510658 -311.526428) (xy 197.542658 -311.526428) (xy 197.542658 -311.755028)
			)
		)
	)
	(zone
		(layer "F.Cu")
		(hatch none 0.5)
		(connect_pads
			(clearance 0)
		)
		(min_thickness 0.25)
		(keepout
			(tracks allowed)
			(vias allowed)
			(pads allowed)
			(copperpour allowed)
			(footprints allowed)
		)
		(placement
			(enabled no)
			(sheetname "")
		)
		(fill
			(thermal_gap 0.5)
			(thermal_bridge_width 0.5)
			(island_removal_mode 0)
		)
		(polygon
			(pts
				(xy 289.231578 -200.51649) (xy 289.231578 -200.072752) (xy 291.556694 -200.072752) (xy 291.556694 -200.51649)
			)
		)
	)
	(zone
		(layer "F.Cu")
		(hatch none 0.5)
		(connect_pads
			(clearance 0)
		)
		(min_thickness 0.25)
		(keepout
			(tracks allowed)
			(vias allowed)
			(pads allowed)
			(copperpour allowed)
			(footprints allowed)
		)
		(placement
			(enabled no)
			(sheetname "")
		)
		(fill
			(thermal_gap 0.5)
			(thermal_bridge_width 0.5)
			(island_removal_mode 0)
		)
		(polygon
			(pts
				(xy 41.29151 -278.716486) (xy 41.29151 -278.272748) (xy 43.616626 -278.272748) (xy 43.616626 -278.716486)
			)
		)
	)
	(zone
		(layer "F.Cu")
		(hatch none 0.5)
		(connect_pads
			(clearance 0)
		)
		(min_thickness 0.25)
		(keepout
			(tracks allowed)
			(vias allowed)
			(pads allowed)
			(copperpour allowed)
			(footprints allowed)
		)
		(placement
			(enabled no)
			(sheetname "")
		)
		(fill
			(thermal_gap 0.5)
			(thermal_bridge_width 0.5)
			(island_removal_mode 0)
		)
		(polygon
			(pts
				(xy 262.50011 -212.416644) (xy 262.50011 -211.972906) (xy 264.825226 -211.972906) (xy 264.825226 -212.416644)
			)
		)
	)
	(zone
		(layer "F.Cu")
		(hatch none 0.5)
		(connect_pads
			(clearance 0)
		)
		(min_thickness 0.25)
		(keepout
			(tracks allowed)
			(vias allowed)
			(pads allowed)
			(copperpour allowed)
			(footprints allowed)
		)
		(placement
			(enabled no)
			(sheetname "")
		)
		(fill
			(thermal_gap 0.5)
			(thermal_bridge_width 0.5)
			(island_removal_mode 0)
		)
		(polygon
			(pts
				(xy 405.731726 -310.90489) (xy 405.731726 -310.67629) (xy 407.763726 -310.67629) (xy 407.763726 -310.90489)
			)
		)
	)
	(zone
		(layer "F.Cu")
		(hatch none 0.5)
		(connect_pads
			(clearance 0)
		)
		(min_thickness 0.25)
		(keepout
			(tracks allowed)
			(vias allowed)
			(pads allowed)
			(copperpour allowed)
			(footprints allowed)
		)
		(placement
			(enabled no)
			(sheetname "")
		)
		(fill
			(thermal_gap 0.5)
			(thermal_bridge_width 0.5)
			(island_removal_mode 0)
		)
		(polygon
			(pts
				(xy 455.094594 -200.407016) (xy 457.126594 -200.407016) (xy 457.126594 -200.178416) (xy 455.094594 -200.178416)
				(xy 454.963276 -200.178416) (xy 454.937368 -200.178416) (xy 454.937368 -200.407016) (xy 454.963276 -200.407016)
			)
		)
	)
	(zone
		(layer "F.Cu")
		(hatch none 0.5)
		(connect_pads
			(clearance 0)
		)
		(min_thickness 0.25)
		(keepout
			(tracks allowed)
			(vias allowed)
			(pads allowed)
			(copperpour allowed)
			(footprints allowed)
		)
		(placement
			(enabled no)
			(sheetname "")
		)
		(fill
			(thermal_gap 0.5)
			(thermal_bridge_width 0.5)
			(island_removal_mode 0)
		)
		(polygon
			(pts
				(xy 455.094594 -312.606944) (xy 457.126594 -312.606944) (xy 457.126594 -312.378344) (xy 455.094594 -312.378344)
				(xy 454.963276 -312.378344) (xy 454.937368 -312.378344) (xy 454.937368 -312.606944) (xy 454.963276 -312.606944)
			)
		)
	)
	(zone
		(layer "F.Cu")
		(hatch none 0.5)
		(connect_pads
			(clearance 0)
		)
		(min_thickness 0.25)
		(keepout
			(tracks allowed)
			(vias allowed)
			(pads allowed)
			(copperpour allowed)
			(footprints allowed)
		)
		(placement
			(enabled no)
			(sheetname "")
		)
		(fill
			(thermal_gap 0.5)
			(thermal_bridge_width 0.5)
			(island_removal_mode 0)
		)
		(polygon
			(pts
				(xy 176.979326 -315.776356) (xy 179.011326 -315.776356) (xy 179.011326 -316.004956) (xy 176.979326 -316.004956)
				(xy 176.843182 -316.004956) (xy 176.796192 -316.004956) (xy 176.796192 -315.776356) (xy 176.843182 -315.776356)
			)
		)
	)
	(zone
		(layer "F.Cu")
		(hatch none 0.5)
		(connect_pads
			(clearance 0)
		)
		(min_thickness 0.25)
		(keepout
			(tracks allowed)
			(vias allowed)
			(pads allowed)
			(copperpour allowed)
			(footprints allowed)
		)
		(placement
			(enabled no)
			(sheetname "")
		)
		(fill
			(thermal_gap 0.5)
			(thermal_bridge_width 0.5)
			(island_removal_mode 0)
		)
		(polygon
			(pts
				(xy 90.408252 -404.802594) (xy 90.408252 -399.959576) (xy 92.292678 -399.959576) (xy 92.292678 -404.802594)
			)
		)
	)
	(zone
		(layer "F.Cu")
		(hatch none 0.5)
		(connect_pads
			(clearance 0)
		)
		(min_thickness 0.25)
		(keepout
			(tracks allowed)
			(vias allowed)
			(pads allowed)
			(copperpour allowed)
			(footprints allowed)
		)
		(placement
			(enabled no)
			(sheetname "")
		)
		(fill
			(thermal_gap 0.5)
			(thermal_bridge_width 0.5)
			(island_removal_mode 0)
		)
		(polygon
			(pts
				(xy 88.691212 -410.948886) (xy 88.691212 -406.105868) (xy 90.575638 -406.105868) (xy 90.575638 -410.948886)
			)
		)
	)
	(zone
		(layer "F.Cu")
		(hatch none 0.5)
		(connect_pads
			(clearance 0)
		)
		(min_thickness 0.25)
		(keepout
			(tracks allowed)
			(vias allowed)
			(pads allowed)
			(copperpour allowed)
			(footprints allowed)
		)
		(placement
			(enabled no)
			(sheetname "")
		)
		(fill
			(thermal_gap 0.5)
			(thermal_bridge_width 0.5)
			(island_removal_mode 0)
		)
		(polygon
			(pts
				(xy 44.735242 -226.86645) (xy 44.735242 -226.422712) (xy 47.060358 -226.422712) (xy 47.060358 -226.86645)
			)
		)
	)
	(zone
		(layer "F.Cu")
		(hatch none 0.5)
		(connect_pads
			(clearance 0)
		)
		(min_thickness 0.25)
		(keepout
			(tracks allowed)
			(vias allowed)
			(pads allowed)
			(copperpour allowed)
			(footprints allowed)
		)
		(placement
			(enabled no)
			(sheetname "")
		)
		(fill
			(thermal_gap 0.5)
			(thermal_bridge_width 0.5)
			(island_removal_mode 0)
		)
		(polygon
			(pts
				(xy 413.275526 -208.90484) (xy 413.275526 -208.67624) (xy 415.307526 -208.67624) (xy 415.307526 -208.90484)
			)
		)
	)
	(zone
		(layer "F.Cu")
		(hatch none 0.5)
		(connect_pads
			(clearance 0)
		)
		(min_thickness 0.25)
		(keepout
			(tracks allowed)
			(vias allowed)
			(pads allowed)
			(copperpour allowed)
			(footprints allowed)
		)
		(placement
			(enabled no)
			(sheetname "")
		)
		(fill
			(thermal_gap 0.5)
			(thermal_bridge_width 0.5)
			(island_removal_mode 0)
		)
		(polygon
			(pts
				(xy 377.571254 -339.369146) (xy 375.823734 -339.369146) (xy 375.823734 -337.433666) (xy 377.571254 -337.433666)
			)
		)
	)
	(zone
		(layer "F.Cu")
		(hatch none 0.5)
		(connect_pads
			(clearance 0)
		)
		(min_thickness 0.25)
		(keepout
			(tracks allowed)
			(vias allowed)
			(pads allowed)
			(copperpour allowed)
			(footprints allowed)
		)
		(placement
			(enabled no)
			(sheetname "")
		)
		(fill
			(thermal_gap 0.5)
			(thermal_bridge_width 0.5)
			(island_removal_mode 0)
		)
		(polygon
			(pts
				(xy 44.735242 -299.966634) (xy 44.735242 -299.522896) (xy 47.060358 -299.522896) (xy 47.060358 -299.966634)
			)
		)
	)
	(zone
		(layer "F.Cu")
		(hatch none 0.5)
		(connect_pads
			(clearance 0)
		)
		(min_thickness 0.25)
		(keepout
			(tracks allowed)
			(vias allowed)
			(pads allowed)
			(copperpour allowed)
			(footprints allowed)
		)
		(placement
			(enabled no)
			(sheetname "")
		)
		(fill
			(thermal_gap 0.5)
			(thermal_bridge_width 0.5)
			(island_removal_mode 0)
		)
		(polygon
			(pts
				(xy 41.29151 -202.216512) (xy 41.29151 -201.772774) (xy 43.616626 -201.772774) (xy 43.616626 -202.216512)
			)
		)
	)
	(zone
		(layer "F.Cu")
		(hatch none 0.5)
		(connect_pads
			(clearance 0)
		)
		(min_thickness 0.25)
		(keepout
			(tracks allowed)
			(vias allowed)
			(pads allowed)
			(copperpour allowed)
			(footprints allowed)
		)
		(placement
			(enabled no)
			(sheetname "")
		)
		(fill
			(thermal_gap 0.5)
			(thermal_bridge_width 0.5)
			(island_removal_mode 0)
		)
		(polygon
			(pts
				(xy 443.450726 -293.05504) (xy 443.450726 -292.82644) (xy 445.482726 -292.82644) (xy 445.482726 -293.05504)
			)
		)
	)
	(zone
		(layer "F.Cu")
		(hatch none 0.5)
		(connect_pads
			(clearance 0)
		)
		(min_thickness 0.25)
		(keepout
			(tracks allowed)
			(vias allowed)
			(pads allowed)
			(copperpour allowed)
			(footprints allowed)
		)
		(placement
			(enabled no)
			(sheetname "")
		)
		(fill
			(thermal_gap 0.5)
			(thermal_bridge_width 0.5)
			(island_removal_mode 0)
		)
		(polygon
			(pts
				(xy 443.450726 -208.054956) (xy 443.450726 -207.826356) (xy 445.482726 -207.826356) (xy 445.482726 -208.054956)
			)
		)
	)
	(zone
		(layer "F.Cu")
		(hatch none 0.5)
		(connect_pads
			(clearance 0)
		)
		(min_thickness 0.25)
		(keepout
			(tracks allowed)
			(vias allowed)
			(pads allowed)
			(copperpour allowed)
			(footprints allowed)
		)
		(placement
			(enabled no)
			(sheetname "")
		)
		(fill
			(thermal_gap 0.5)
			(thermal_bridge_width 0.5)
			(island_removal_mode 0)
		)
		(polygon
			(pts
				(xy 210.32216 -392.862308) (xy 210.32216 -391.698988) (xy 211.90204 -391.698988) (xy 211.90204 -392.862308)
			)
		)
	)
	(zone
		(layer "F.Cu")
		(hatch none 0.5)
		(connect_pads
			(clearance 0)
		)
		(min_thickness 0.25)
		(keepout
			(tracks allowed)
			(vias allowed)
			(pads allowed)
			(copperpour allowed)
			(footprints allowed)
		)
		(placement
			(enabled no)
			(sheetname "")
		)
		(fill
			(thermal_gap 0.5)
			(thermal_bridge_width 0.5)
			(island_removal_mode 0)
		)
		(polygon
			(pts
				(xy 418.798756 -361.958128) (xy 415.263076 -361.958128) (xy 415.263076 -359.875328) (xy 418.798756 -359.875328)
			)
		)
	)
	(zone
		(layer "F.Cu")
		(hatch none 0.5)
		(connect_pads
			(clearance 0)
		)
		(min_thickness 0.25)
		(keepout
			(tracks allowed)
			(vias allowed)
			(pads allowed)
			(copperpour allowed)
			(footprints allowed)
		)
		(placement
			(enabled no)
			(sheetname "")
		)
		(fill
			(thermal_gap 0.5)
			(thermal_bridge_width 0.5)
			(island_removal_mode 0)
		)
		(polygon
			(pts
				(xy 440.006994 -295.376346) (xy 442.038994 -295.376346) (xy 442.038994 -295.604946) (xy 440.006994 -295.604946)
				(xy 439.87085 -295.604946) (xy 439.82386 -295.604946) (xy 439.82386 -295.376346) (xy 439.87085 -295.376346)
			)
		)
	)
	(zone
		(layer "F.Cu")
		(hatch none 0.5)
		(connect_pads
			(clearance 0)
		)
		(min_thickness 0.25)
		(keepout
			(tracks allowed)
			(vias allowed)
			(pads allowed)
			(copperpour allowed)
			(footprints allowed)
		)
		(placement
			(enabled no)
			(sheetname "")
		)
		(fill
			(thermal_gap 0.5)
			(thermal_bridge_width 0.5)
			(island_removal_mode 0)
		)
		(polygon
			(pts
				(xy 289.231578 -268.922754) (xy 291.556694 -268.922754) (xy 291.630608 -268.922754) (xy 291.630608 -269.890748)
				(xy 289.09772 -269.890748) (xy 289.09772 -268.922754)
			)
		)
	)
	(zone
		(layer "F.Cu")
		(hatch none 0.5)
		(connect_pads
			(clearance 0)
		)
		(min_thickness 0.25)
		(keepout
			(tracks allowed)
			(vias allowed)
			(pads allowed)
			(copperpour allowed)
			(footprints allowed)
		)
		(placement
			(enabled no)
			(sheetname "")
		)
		(fill
			(thermal_gap 0.5)
			(thermal_bridge_width 0.5)
			(island_removal_mode 0)
		)
		(polygon
			(pts
				(xy 274.143978 -209.866484) (xy 274.143978 -209.422746) (xy 276.469094 -209.422746) (xy 276.469094 -209.866484)
			)
		)
	)
	(zone
		(layer "F.Cu")
		(hatch none 0.5)
		(connect_pads
			(clearance 0)
		)
		(min_thickness 0.25)
		(keepout
			(tracks allowed)
			(vias allowed)
			(pads allowed)
			(copperpour allowed)
			(footprints allowed)
		)
		(placement
			(enabled no)
			(sheetname "")
		)
		(fill
			(thermal_gap 0.5)
			(thermal_bridge_width 0.5)
			(island_removal_mode 0)
		)
		(polygon
			(pts
				(xy 207.154526 -285.176214) (xy 209.186526 -285.176214) (xy 209.186526 -285.404814) (xy 207.154526 -285.404814)
				(xy 207.023208 -285.404814) (xy 206.9973 -285.404814) (xy 206.9973 -285.176214) (xy 207.023208 -285.176214)
			)
		)
	)
	(zone
		(layer "F.Cu")
		(hatch none 0.5)
		(connect_pads
			(clearance 0)
		)
		(min_thickness 0.25)
		(keepout
			(tracks allowed)
			(vias allowed)
			(pads allowed)
			(copperpour allowed)
			(footprints not_allowed)
		)
		(placement
			(enabled no)
			(sheetname "")
		)
		(fill
			(thermal_gap 0.5)
			(thermal_bridge_width 0.5)
			(island_removal_mode 0)
		)
		(polygon
			(pts
				(xy 7.20598 -168.661842) (xy 7.20598 -182.236872) (xy 2.999994 -182.236872) (xy 2.999994 -187.661804)
				(xy 6.140704 -187.661804) (xy 6.140704 -185.091832) (xy 67.04711 -185.091832) (xy 67.04711 -187.661804)
				(xy 72.497188 -187.661804) (xy 72.497188 -168.661842)
			)
		)
	)
	(zone
		(layer "F.Cu")
		(hatch none 0.5)
		(connect_pads
			(clearance 0)
		)
		(min_thickness 0.25)
		(keepout
			(tracks allowed)
			(vias allowed)
			(pads allowed)
			(copperpour allowed)
			(footprints allowed)
		)
		(placement
			(enabled no)
			(sheetname "")
		)
		(fill
			(thermal_gap 0.5)
			(thermal_bridge_width 0.5)
			(island_removal_mode 0)
		)
		(polygon
			(pts
				(xy 259.056378 -278.716486) (xy 259.056378 -278.272748) (xy 261.381494 -278.272748) (xy 261.381494 -278.716486)
			)
		)
	)
	(zone
		(layer "F.Cu")
		(hatch none 0.5)
		(connect_pads
			(clearance 0)
		)
		(min_thickness 0.25)
		(keepout
			(tracks allowed)
			(vias allowed)
			(pads allowed)
			(copperpour allowed)
			(footprints allowed)
		)
		(placement
			(enabled no)
			(sheetname "")
		)
		(fill
			(thermal_gap 0.5)
			(thermal_bridge_width 0.5)
			(island_removal_mode 0)
		)
		(polygon
			(pts
				(xy 84.870798 -260.898386) (xy 85.073744 -260.69544) (xy 85.073744 -260.65226) (xy 84.630006 -260.208522)
				(xy 84.507832 -260.208522) (xy 84.37499 -260.341618) (xy 84.37499 -260.445758) (xy 84.827618 -260.898386)
			)
		)
	)
	(zone
		(layer "F.Cu")
		(hatch none 0.5)
		(connect_pads
			(clearance 0)
		)
		(min_thickness 0.25)
		(keepout
			(tracks allowed)
			(vias allowed)
			(pads allowed)
			(copperpour allowed)
			(footprints allowed)
		)
		(placement
			(enabled no)
			(sheetname "")
		)
		(fill
			(thermal_gap 0.5)
			(thermal_bridge_width 0.5)
			(island_removal_mode 0)
		)
		(polygon
			(pts
				(xy 63.977012 -248.116598) (xy 63.977012 -247.67286) (xy 66.186812 -247.67286) (xy 66.186812 -248.116598)
			)
		)
	)
	(zone
		(layer "F.Cu")
		(hatch none 0.5)
		(connect_pads
			(clearance 0)
		)
		(min_thickness 0.25)
		(keepout
			(tracks allowed)
			(vias allowed)
			(pads allowed)
			(copperpour allowed)
			(footprints allowed)
		)
		(placement
			(enabled no)
			(sheetname "")
		)
		(fill
			(thermal_gap 0.5)
			(thermal_bridge_width 0.5)
			(island_removal_mode 0)
		)
		(polygon
			(pts
				(xy 385.27736 -217.678508) (xy 385.56438 -217.678508) (xy 385.59486 -217.648028) (xy 385.59486 -217.020648)
				(xy 385.5085 -216.934288) (xy 385.32054 -216.934288) (xy 385.24688 -217.007948) (xy 385.24688 -217.648028)
			)
		)
	)
	(zone
		(layer "F.Cu")
		(hatch none 0.5)
		(connect_pads
			(clearance 0)
		)
		(min_thickness 0.25)
		(keepout
			(tracks allowed)
			(vias allowed)
			(pads allowed)
			(copperpour allowed)
			(footprints allowed)
		)
		(placement
			(enabled no)
			(sheetname "")
		)
		(fill
			(thermal_gap 0.5)
			(thermal_bridge_width 0.5)
			(island_removal_mode 0)
		)
		(polygon
			(pts
				(xy 195.510658 -282.854908) (xy 195.510658 -282.626308) (xy 197.542658 -282.626308) (xy 197.542658 -282.854908)
			)
		)
	)
	(zone
		(layer "F.Cu")
		(hatch none 0.5)
		(connect_pads
			(clearance 0)
		)
		(min_thickness 0.25)
		(keepout
			(tracks allowed)
			(vias allowed)
			(pads allowed)
			(copperpour allowed)
			(footprints not_allowed)
		)
		(placement
			(enabled no)
			(sheetname "")
		)
		(fill
			(thermal_gap 0.5)
			(thermal_bridge_width 0.5)
			(island_removal_mode 0)
		)
		(polygon
			(pts
				(arc
					(start 290.079938 -419.999922)
					(mid 287.98012 -422.09974)
					(end 285.880048 -419.999922)
				)
				(arc
					(start 285.880048 -419.999922)
					(mid 287.98012 -417.89985)
					(end 290.079938 -419.999922)
				)
			)
		)
	)
	(zone
		(layer "F.Cu")
		(hatch none 0.5)
		(connect_pads
			(clearance 0)
		)
		(min_thickness 0.25)
		(keepout
			(tracks allowed)
			(vias allowed)
			(pads allowed)
			(copperpour allowed)
			(footprints allowed)
		)
		(placement
			(enabled no)
			(sheetname "")
		)
		(fill
			(thermal_gap 0.5)
			(thermal_bridge_width 0.5)
			(island_removal_mode 0)
		)
		(polygon
			(pts
				(xy 179.179728 -351.527618) (xy 179.179728 -355.533198) (xy 179.659788 -356.013258) (xy 181.724808 -356.013258)
				(xy 181.996588 -355.741478) (xy 181.996588 -353.887278) (xy 182.248048 -353.635818) (xy 184.168288 -353.635818)
				(xy 184.584848 -353.219258) (xy 184.584848 -351.728278) (xy 183.937148 -351.080578) (xy 179.626768 -351.080578)
			)
		)
	)
	(zone
		(layer "F.Cu")
		(hatch none 0.5)
		(connect_pads
			(clearance 0)
		)
		(min_thickness 0.25)
		(keepout
			(tracks allowed)
			(vias allowed)
			(pads allowed)
			(copperpour allowed)
			(footprints allowed)
		)
		(placement
			(enabled no)
			(sheetname "")
		)
		(fill
			(thermal_gap 0.5)
			(thermal_bridge_width 0.5)
			(island_removal_mode 0)
		)
		(polygon
			(pts
				(xy 44.735242 -209.0166) (xy 44.735242 -208.572862) (xy 47.060358 -208.572862) (xy 47.060358 -209.0166)
			)
		)
	)
	(zone
		(layer "F.Cu")
		(hatch none 0.5)
		(connect_pads
			(clearance 0)
		)
		(min_thickness 0.25)
		(keepout
			(tracks allowed)
			(vias allowed)
			(pads allowed)
			(copperpour allowed)
			(footprints allowed)
		)
		(placement
			(enabled no)
			(sheetname "")
		)
		(fill
			(thermal_gap 0.5)
			(thermal_bridge_width 0.5)
			(island_removal_mode 0)
		)
		(polygon
			(pts
				(xy 169.177462 -319.243202) (xy 169.177462 -317.52667) (xy 171.793662 -317.52667) (xy 171.793662 -319.243202)
				(xy 171.793662 -319.964308) (xy 169.177462 -319.964308) (xy 169.177462 -319.428114)
			)
		)
	)
	(zone
		(layer "F.Cu")
		(hatch none 0.5)
		(connect_pads
			(clearance 0)
		)
		(min_thickness 0.25)
		(keepout
			(tracks not_allowed)
			(vias allowed)
			(pads allowed)
			(copperpour not_allowed)
			(footprints allowed)
		)
		(placement
			(enabled no)
			(sheetname "")
		)
		(fill
			(thermal_gap 0.5)
			(thermal_bridge_width 0.5)
			(island_removal_mode 0)
		)
		(polygon
			(pts
				(xy 416.209988 -159.685736) (xy 415.960306 -159.685736) (xy 415.960306 -161.856166) (xy 416.10026 -161.99612)
				(xy 416.266122 -161.99612) (xy 416.266122 -162.133788) (xy 418.313362 -162.133788) (xy 418.313362 -163.987988)
				(xy 418.072316 -163.987988) (xy 418.072316 -164.230304) (xy 418.5539 -164.230304) (xy 418.5539 -160.28162)
				(xy 418.368988 -160.466532) (xy 418.368988 -161.84245) (xy 416.209988 -161.84245)
			)
		)
	)
	(zone
		(layer "F.Cu")
		(hatch none 0.5)
		(connect_pads
			(clearance 0)
		)
		(min_thickness 0.25)
		(keepout
			(tracks allowed)
			(vias allowed)
			(pads allowed)
			(copperpour allowed)
			(footprints allowed)
		)
		(placement
			(enabled no)
			(sheetname "")
		)
		(fill
			(thermal_gap 0.5)
			(thermal_bridge_width 0.5)
			(island_removal_mode 0)
		)
		(polygon
			(pts
				(xy 86.697566 -251.86005) (xy 87.963502 -250.594114) (xy 87.962994 -229.543102) (xy 86.389972 -227.97008)
				(xy 84.969858 -227.97008) (xy 84.39785 -227.398072) (xy 84.39785 -223.591628) (xy 85.048852 -222.940626)
				(xy 87.415624 -222.940626) (xy 87.879428 -222.476822) (xy 87.879428 -219.715842) (xy 86.823804 -218.660218)
				(xy 86.443058 -218.660218) (xy 85.820504 -218.037664) (xy 85.815424 -218.037664) (xy 85.510624 -217.732864)
				(xy 85.495638 -217.717878) (xy 85.437472 -217.717878) (xy 85.05063 -218.10472) (xy 85.05063 -218.44508)
				(xy 83.765644 -219.730066) (xy 83.758786 -219.730066) (xy 83.591654 -219.562934) (xy 83.485228 -219.562934)
				(xy 83.115404 -219.932758) (xy 83.115404 -220.028008) (xy 83.196938 -220.109542) (xy 84.124292 -221.036896)
				(xy 83.321906 -221.839282) (xy 83.321906 -221.937326) (xy 83.32343 -221.938596) (xy 83.32343 -222.420688)
				(xy 83.39963 -222.496888) (xy 83.85683 -222.954088) (xy 83.85683 -227.70465) (xy 84.056982 -227.904802)
				(xy 84.056982 -228.773228) (xy 83.964018 -228.866192) (xy 83.69046 -228.866192) (xy 83.281012 -229.27564)
				(xy 83.281012 -229.35946) (xy 83.351116 -229.429564) (xy 83.782408 -229.860856) (xy 83.782408 -230.785162)
				(xy 83.369404 -231.198166) (xy 83.369404 -232.96118) (xy 83.446874 -233.03865) (xy 83.653884 -233.03865)
				(xy 83.800442 -233.03865) (xy 83.813904 -233.052112) (xy 83.813904 -233.610658) (xy 83.739228 -233.685334)
				(xy 83.518756 -233.685334) (xy 83.390994 -233.813096) (xy 83.390994 -237.449868) (xy 83.433666 -237.49254)
				(xy 83.501484 -237.49254) (xy 83.99145 -237.49254) (xy 83.99145 -237.639352) (xy 84.039456 -237.687358)
				(xy 84.039456 -238.242348) (xy 83.85683 -238.424974) (xy 83.85683 -238.722408) (xy 83.444588 -239.13465)
				(xy 83.269582 -239.13465) (xy 82.738214 -239.666018) (xy 82.738214 -241.113818) (xy 83.72983 -242.105434)
				(xy 83.72983 -244.758972) (xy 84.019136 -244.758972) (xy 84.019136 -245.9228) (xy 83.727798 -245.9228)
				(xy 83.727798 -247.802654) (xy 83.900264 -247.97512) (xy 83.900264 -248.447052) (xy 83.622642 -248.724674)
				(xy 83.622642 -249.268234) (xy 83.636612 -249.282204) (xy 83.767676 -249.282204) (xy 83.813142 -249.32767)
				(xy 83.813142 -251.714254) (xy 83.958938 -251.86005)
			)
		)
	)
	(zone
		(layer "F.Cu")
		(hatch none 0.5)
		(connect_pads
			(clearance 0)
		)
		(min_thickness 0.25)
		(keepout
			(tracks not_allowed)
			(vias allowed)
			(pads allowed)
			(copperpour not_allowed)
			(footprints allowed)
		)
		(placement
			(enabled no)
			(sheetname "")
		)
		(fill
			(thermal_gap 0.5)
			(thermal_bridge_width 0.5)
			(island_removal_mode 0)
		)
		(polygon
			(pts
				(arc
					(start 262.850122 -22.29993)
					(mid 265.650218 -19.499834)
					(end 268.45006 -22.29993)
				)
				(arc
					(start 268.45006 -22.29993)
					(mid 265.650218 -25.099772)
					(end 262.850122 -22.29993)
				)
			)
		)
	)
	(zone
		(layer "F.Cu")
		(hatch none 0.5)
		(connect_pads
			(clearance 0)
		)
		(min_thickness 0.25)
		(keepout
			(tracks allowed)
			(vias allowed)
			(pads allowed)
			(copperpour allowed)
			(footprints allowed)
		)
		(placement
			(enabled no)
			(sheetname "")
		)
		(fill
			(thermal_gap 0.5)
			(thermal_bridge_width 0.5)
			(island_removal_mode 0)
		)
		(polygon
			(pts
				(xy 335.46542 -216.075768) (xy 335.75244 -216.075768) (xy 335.78292 -216.045288) (xy 335.78292 -215.417908)
				(xy 335.69656 -215.331548) (xy 335.5086 -215.331548) (xy 335.43494 -215.405208) (xy 335.43494 -216.045288)
			)
		)
	)
	(zone
		(layer "F.Cu")
		(hatch none 0.5)
		(connect_pads
			(clearance 0)
		)
		(min_thickness 0.25)
		(keepout
			(tracks allowed)
			(vias allowed)
			(pads allowed)
			(copperpour allowed)
			(footprints not_allowed)
		)
		(placement
			(enabled no)
			(sheetname "")
		)
		(fill
			(thermal_gap 0.5)
			(thermal_bridge_width 0.5)
			(island_removal_mode 0)
		)
		(polygon
			(pts
				(arc
					(start 80.3148 -353.525074)
					(mid 81.915 -351.924874)
					(end 83.514946 -353.525074)
				)
				(arc
					(start 83.514946 -353.525074)
					(mid 81.915 -355.12502)
					(end 80.3148 -353.525074)
				)
			)
		)
	)
	(zone
		(layer "F.Cu")
		(hatch none 0.5)
		(connect_pads
			(clearance 0)
		)
		(min_thickness 0.25)
		(keepout
			(tracks allowed)
			(vias allowed)
			(pads allowed)
			(copperpour allowed)
			(footprints allowed)
		)
		(placement
			(enabled no)
			(sheetname "")
		)
		(fill
			(thermal_gap 0.5)
			(thermal_bridge_width 0.5)
			(island_removal_mode 0)
		)
		(polygon
			(pts
				(xy 458.538326 -252.25502) (xy 458.538326 -252.02642) (xy 460.570326 -252.02642) (xy 460.570326 -252.25502)
			)
		)
	)
	(zone
		(layer "F.Cu")
		(hatch none 0.5)
		(connect_pads
			(clearance 0)
		)
		(min_thickness 0.25)
		(keepout
			(tracks allowed)
			(vias allowed)
			(pads allowed)
			(copperpour allowed)
			(footprints allowed)
		)
		(placement
			(enabled no)
			(sheetname "")
		)
		(fill
			(thermal_gap 0.5)
			(thermal_bridge_width 0.5)
			(island_removal_mode 0)
		)
		(polygon
			(pts
				(xy 416.914584 -404.802594) (xy 416.914584 -399.959576) (xy 418.79901 -399.959576) (xy 418.79901 -404.802594)
			)
		)
	)
	(zone
		(layer "F.Cu")
		(hatch none 0.5)
		(connect_pads
			(clearance 0)
		)
		(min_thickness 0.25)
		(keepout
			(tracks allowed)
			(vias allowed)
			(pads allowed)
			(copperpour allowed)
			(footprints not_allowed)
		)
		(placement
			(enabled no)
			(sheetname "")
		)
		(fill
			(thermal_gap 0.5)
			(thermal_bridge_width 0.5)
			(island_removal_mode 0)
		)
		(polygon
			(pts
				(xy 14.684502 -330.091796) (xy 20.784312 -330.091796) (xy 20.784312 -186.09183) (xy 14.684502 -186.09183)
			)
		)
	)
	(zone
		(layer "F.Cu")
		(hatch none 0.5)
		(connect_pads
			(clearance 0)
		)
		(min_thickness 0.25)
		(keepout
			(tracks allowed)
			(vias allowed)
			(pads allowed)
			(copperpour allowed)
			(footprints allowed)
		)
		(placement
			(enabled no)
			(sheetname "")
		)
		(fill
			(thermal_gap 0.5)
			(thermal_bridge_width 0.5)
			(island_removal_mode 0)
		)
		(polygon
			(pts
				(xy 274.143978 -308.46649) (xy 274.143978 -308.022752) (xy 276.469094 -308.022752) (xy 276.469094 -308.46649)
			)
		)
	)
	(zone
		(layer "F.Cu")
		(hatch none 0.5)
		(connect_pads
			(clearance 0)
		)
		(min_thickness 0.25)
		(keepout
			(tracks allowed)
			(vias allowed)
			(pads allowed)
			(copperpour allowed)
			(footprints allowed)
		)
		(placement
			(enabled no)
			(sheetname "")
		)
		(fill
			(thermal_gap 0.5)
			(thermal_bridge_width 0.5)
			(island_removal_mode 0)
		)
		(polygon
			(pts
				(xy 210.598258 -245.454932) (xy 210.598258 -245.226332) (xy 212.630258 -245.226332) (xy 212.630258 -245.454932)
			)
		)
	)
	(zone
		(layer "F.Cu")
		(hatch none 0.5)
		(connect_pads
			(clearance 0)
		)
		(min_thickness 0.25)
		(keepout
			(tracks allowed)
			(vias allowed)
			(pads allowed)
			(copperpour allowed)
			(footprints allowed)
		)
		(placement
			(enabled no)
			(sheetname "")
		)
		(fill
			(thermal_gap 0.5)
			(thermal_bridge_width 0.5)
			(island_removal_mode 0)
		)
		(polygon
			(pts
				(xy 409.831794 -209.754978) (xy 409.831794 -209.526378) (xy 411.863794 -209.526378) (xy 411.863794 -209.754978)
			)
		)
	)
	(zone
		(layer "F.Cu")
		(hatch none 0.5)
		(connect_pads
			(clearance 0)
		)
		(min_thickness 0.25)
		(keepout
			(tracks allowed)
			(vias allowed)
			(pads allowed)
			(copperpour allowed)
			(footprints allowed)
		)
		(placement
			(enabled no)
			(sheetname "")
		)
		(fill
			(thermal_gap 0.5)
			(thermal_bridge_width 0.5)
			(island_removal_mode 0)
		)
		(polygon
			(pts
				(xy 22.0091 -386.59816) (xy 22.0091 -384.14706) (xy 24.18334 -384.14706) (xy 24.18334 -386.59816)
			)
		)
	)
	(zone
		(layer "F.Cu")
		(hatch none 0.5)
		(connect_pads
			(clearance 0)
		)
		(min_thickness 0.25)
		(keepout
			(tracks allowed)
			(vias allowed)
			(pads allowed)
			(copperpour allowed)
			(footprints allowed)
		)
		(placement
			(enabled no)
			(sheetname "")
		)
		(fill
			(thermal_gap 0.5)
			(thermal_bridge_width 0.5)
			(island_removal_mode 0)
		)
		(polygon
			(pts
				(xy 157.791658 -238.654844) (xy 157.791658 -238.426244) (xy 159.823658 -238.426244) (xy 159.823658 -238.654844)
				(xy 159.831024 -238.66221) (xy 160.326578 -238.66221) (xy 160.494218 -238.82985) (xy 160.494218 -239.15497)
				(xy 160.388808 -239.26038) (xy 159.558228 -239.26038) (xy 159.483298 -239.33531) (xy 157.318456 -239.33531)
				(xy 157.224984 -239.241838) (xy 157.224984 -238.787686) (xy 157.317694 -238.694976) (xy 157.766766 -238.694976)
				(xy 157.806898 -238.654844)
			)
		)
	)
	(zone
		(layer "F.Cu")
		(hatch none 0.5)
		(connect_pads
			(clearance 0)
		)
		(min_thickness 0.25)
		(keepout
			(tracks allowed)
			(vias allowed)
			(pads allowed)
			(copperpour allowed)
			(footprints not_allowed)
		)
		(placement
			(enabled no)
			(sheetname "")
		)
		(fill
			(thermal_gap 0.5)
			(thermal_bridge_width 0.5)
			(island_removal_mode 0)
		)
		(polygon
			(pts
				(xy 222.670116 -327.589896) (xy 249.130058 -327.589896) (xy 249.130058 -277.204932) (xy 245.629938 -277.204932)
				(xy 245.629938 -249.499882) (xy 249.130058 -249.499882) (xy 249.130058 -220.000068) (xy 245.629938 -220.000068)
				(xy 245.629938 -191.499998) (xy 249.130058 -191.499998) (xy 249.130058 -177.200052)
				(arc
					(start 248.899934 -177.200052)
					(mid 245.364407 -175.735589)
					(end 243.899944 -172.200062)
				)
				(xy 243.899944 -161.699956) (xy 243.899944 -107.199938) (xy 227.899976 -107.199938)
				(arc
					(start 227.899976 -172.200062)
					(mid 226.435513 -175.735589)
					(end 222.899986 -177.200052)
				)
				(xy 222.670116 -177.200052) (xy 222.670116 -191.499998) (xy 226.169982 -191.499998) (xy 226.169982 -220.000068)
				(xy 222.670116 -220.000068) (xy 222.670116 -249.499882) (xy 226.169982 -249.499882) (xy 226.169982 -277.199852)
				(xy 222.670116 -277.199852)
			)
		)
	)
	(zone
		(layer "F.Cu")
		(hatch none 0.5)
		(connect_pads
			(clearance 0)
		)
		(min_thickness 0.25)
		(keepout
			(tracks not_allowed)
			(vias allowed)
			(pads allowed)
			(copperpour not_allowed)
			(footprints allowed)
		)
		(placement
			(enabled no)
			(sheetname "")
		)
		(fill
			(thermal_gap 0.5)
			(thermal_bridge_width 0.5)
			(island_removal_mode 0)
		)
		(polygon
			(pts
				(arc
					(start 80.3148 -353.525074)
					(mid 81.914746 -351.925128)
					(end 83.514692 -353.525074)
				)
				(arc
					(start 83.514692 -353.525074)
					(mid 81.914746 -355.12502)
					(end 80.3148 -353.525074)
				)
			)
		)
	)
	(zone
		(layer "F.Cu")
		(hatch none 0.5)
		(connect_pads
			(clearance 0)
		)
		(min_thickness 0.25)
		(keepout
			(tracks allowed)
			(vias allowed)
			(pads allowed)
			(copperpour allowed)
			(footprints allowed)
		)
		(placement
			(enabled no)
			(sheetname "")
		)
		(fill
			(thermal_gap 0.5)
			(thermal_bridge_width 0.5)
			(island_removal_mode 0)
		)
		(polygon
			(pts
				(xy 405.763222 -247.154954) (xy 405.763222 -246.926354) (xy 407.719022 -246.926354) (xy 407.719022 -247.154954)
			)
		)
	)
	(zone
		(layer "F.Cu")
		(hatch none 0.5)
		(connect_pads
			(clearance 0)
		)
		(min_thickness 0.25)
		(keepout
			(tracks allowed)
			(vias allowed)
			(pads allowed)
			(copperpour allowed)
			(footprints allowed)
		)
		(placement
			(enabled no)
			(sheetname "")
		)
		(fill
			(thermal_gap 0.5)
			(thermal_bridge_width 0.5)
			(island_removal_mode 0)
		)
		(polygon
			(pts
				(xy 439.74893 -319.243202) (xy 439.74893 -316.881002) (xy 442.36513 -316.881002) (xy 442.36513 -319.243202)
			)
		)
	)
	(zone
		(layer "F.Cu")
		(hatch none 0.5)
		(connect_pads
			(clearance 0)
		)
		(min_thickness 0.25)
		(keepout
			(tracks allowed)
			(vias allowed)
			(pads allowed)
			(copperpour allowed)
			(footprints allowed)
		)
		(placement
			(enabled no)
			(sheetname "")
		)
		(fill
			(thermal_gap 0.5)
			(thermal_bridge_width 0.5)
			(island_removal_mode 0)
		)
		(polygon
			(pts
				(xy 311.84088 -251.516642) (xy 311.84088 -251.072904) (xy 314.17768 -251.072904) (xy 314.17768 -251.516642)
			)
		)
	)
	(zone
		(layer "F.Cu")
		(hatch none 0.5)
		(connect_pads
			(clearance 0)
		)
		(min_thickness 0.25)
		(keepout
			(tracks allowed)
			(vias allowed)
			(pads allowed)
			(copperpour allowed)
			(footprints allowed)
		)
		(placement
			(enabled no)
			(sheetname "")
		)
		(fill
			(thermal_gap 0.5)
			(thermal_bridge_width 0.5)
			(island_removal_mode 0)
		)
		(polygon
			(pts
				(xy 413.275526 -252.25502) (xy 413.275526 -252.02642) (xy 415.307526 -252.02642) (xy 415.307526 -252.25502)
			)
		)
	)
	(zone
		(layer "F.Cu")
		(hatch none 0.5)
		(connect_pads
			(clearance 0)
		)
		(min_thickness 0.25)
		(keepout
			(tracks allowed)
			(vias allowed)
			(pads allowed)
			(copperpour allowed)
			(footprints not_allowed)
		)
		(placement
			(enabled no)
			(sheetname "")
		)
		(fill
			(thermal_gap 0.5)
			(thermal_bridge_width 0.5)
			(island_removal_mode 0)
		)
		(polygon
			(pts
				(xy 443.47257 -330.091796) (xy 449.57238 -330.091796) (xy 449.57238 -186.09183) (xy 443.47257 -186.09183)
			)
		)
	)
	(zone
		(layer "F.Cu")
		(hatch none 0.5)
		(connect_pads
			(clearance 0)
		)
		(min_thickness 0.25)
		(keepout
			(tracks allowed)
			(vias allowed)
			(pads allowed)
			(copperpour allowed)
			(footprints allowed)
		)
		(placement
			(enabled no)
			(sheetname "")
		)
		(fill
			(thermal_gap 0.5)
			(thermal_bridge_width 0.5)
			(island_removal_mode 0)
		)
		(polygon
			(pts
				(xy 455.094594 -246.304816) (xy 455.094594 -246.076216) (xy 457.126594 -246.076216) (xy 457.126594 -246.304816)
			)
		)
	)
	(zone
		(layer "F.Cu")
		(hatch none 0.5)
		(connect_pads
			(clearance 0)
		)
		(min_thickness 0.25)
		(keepout
			(tracks not_allowed)
			(vias allowed)
			(pads allowed)
			(copperpour not_allowed)
			(footprints allowed)
		)
		(placement
			(enabled no)
			(sheetname "")
		)
		(fill
			(thermal_gap 0.5)
			(thermal_bridge_width 0.5)
			(island_removal_mode 0)
		)
		(polygon
			(pts
				(arc
					(start 233.849926 -352.49993)
					(mid 236.650022 -349.699834)
					(end 239.450118 -352.49993)
				)
				(arc
					(start 239.450118 -352.49993)
					(mid 236.650022 -355.300026)
					(end 233.849926 -352.49993)
				)
			)
		)
	)
	(zone
		(layer "F.Cu")
		(hatch none 0.5)
		(connect_pads
			(clearance 0)
		)
		(min_thickness 0.25)
		(keepout
			(tracks allowed)
			(vias allowed)
			(pads allowed)
			(copperpour allowed)
			(footprints not_allowed)
		)
		(placement
			(enabled no)
			(sheetname "")
		)
		(fill
			(thermal_gap 0.5)
			(thermal_bridge_width 0.5)
			(island_removal_mode 0)
		)
		(polygon
			(pts
				(arc
					(start 378.100082 -22.29993)
					(mid 380.900178 -19.499834)
					(end 383.70002 -22.29993)
				)
				(arc
					(start 383.70002 -22.29993)
					(mid 380.900178 -25.099772)
					(end 378.100082 -22.29993)
				)
			)
		)
	)
	(zone
		(layer "F.Cu")
		(hatch none 0.5)
		(connect_pads
			(clearance 0)
		)
		(min_thickness 0.25)
		(keepout
			(tracks allowed)
			(vias allowed)
			(pads allowed)
			(copperpour allowed)
			(footprints allowed)
		)
		(placement
			(enabled no)
			(sheetname "")
		)
		(fill
			(thermal_gap 0.5)
			(thermal_bridge_width 0.5)
			(island_removal_mode 0)
		)
		(polygon
			(pts
				(xy 62.839092 -404.802594) (xy 62.839092 -399.959576) (xy 64.723518 -399.959576) (xy 64.723518 -404.802594)
			)
		)
	)
	(zone
		(layer "F.Cu")
		(hatch none 0.5)
		(connect_pads
			(clearance 0)
		)
		(min_thickness 0.25)
		(keepout
			(tracks allowed)
			(vias allowed)
			(pads allowed)
			(copperpour allowed)
			(footprints allowed)
		)
		(placement
			(enabled no)
			(sheetname "")
		)
		(fill
			(thermal_gap 0.5)
			(thermal_bridge_width 0.5)
			(island_removal_mode 0)
		)
		(polygon
			(pts
				(xy 48.858678 -18.570702) (xy 48.858678 -15.436088) (xy 50.63744 -15.436088) (xy 50.63744 -18.570702)
			)
		)
	)
	(zone
		(layer "F.Cu")
		(hatch none 0.5)
		(connect_pads
			(clearance 0)
		)
		(min_thickness 0.25)
		(keepout
			(tracks allowed)
			(vias allowed)
			(pads allowed)
			(copperpour allowed)
			(footprints allowed)
		)
		(placement
			(enabled no)
			(sheetname "")
		)
		(fill
			(thermal_gap 0.5)
			(thermal_bridge_width 0.5)
			(island_removal_mode 0)
		)
		(polygon
			(pts
				(xy 428.363126 -310.90489) (xy 428.363126 -310.67629) (xy 430.395126 -310.67629) (xy 430.395126 -310.90489)
			)
		)
	)
	(zone
		(layer "F.Cu")
		(hatch none 0.5)
		(connect_pads
			(clearance 0)
		)
		(min_thickness 0.25)
		(keepout
			(tracks allowed)
			(vias allowed)
			(pads allowed)
			(copperpour allowed)
			(footprints allowed)
		)
		(placement
			(enabled no)
			(sheetname "")
		)
		(fill
			(thermal_gap 0.5)
			(thermal_bridge_width 0.5)
			(island_removal_mode 0)
		)
		(polygon
			(pts
				(xy 207.154526 -216.326466) (xy 209.186526 -216.326466) (xy 209.186526 -216.555066) (xy 207.154526 -216.555066)
				(xy 207.018382 -216.555066) (xy 206.971392 -216.555066) (xy 206.971392 -216.326466) (xy 207.018382 -216.326466)
			)
		)
	)
	(zone
		(layer "F.Cu")
		(hatch none 0.5)
		(connect_pads
			(clearance 0)
		)
		(min_thickness 0.25)
		(keepout
			(tracks allowed)
			(vias allowed)
			(pads allowed)
			(copperpour allowed)
			(footprints allowed)
		)
		(placement
			(enabled no)
			(sheetname "")
		)
		(fill
			(thermal_gap 0.5)
			(thermal_bridge_width 0.5)
			(island_removal_mode 0)
		)
		(polygon
			(pts
				(xy 38.2016 -359.179368) (xy 38.2016 -355.813868) (xy 43.59402 -355.813868) (xy 43.59402 -359.179368)
			)
		)
	)
	(zone
		(layer "F.Cu")
		(hatch none 0.5)
		(connect_pads
			(clearance 0)
		)
		(min_thickness 0.25)
		(keepout
			(tracks allowed)
			(vias allowed)
			(pads allowed)
			(copperpour allowed)
			(footprints allowed)
		)
		(placement
			(enabled no)
			(sheetname "")
		)
		(fill
			(thermal_gap 0.5)
			(thermal_bridge_width 0.5)
			(island_removal_mode 0)
		)
		(polygon
			(pts
				(xy 428.363126 -220.804994) (xy 428.363126 -220.576394) (xy 430.395126 -220.576394) (xy 430.395126 -220.804994)
			)
		)
	)
	(zone
		(layer "F.Cu")
		(hatch none 0.5)
		(connect_pads
			(clearance 0)
		)
		(min_thickness 0.25)
		(keepout
			(tracks allowed)
			(vias allowed)
			(pads allowed)
			(copperpour allowed)
			(footprints allowed)
		)
		(placement
			(enabled no)
			(sheetname "")
		)
		(fill
			(thermal_gap 0.5)
			(thermal_bridge_width 0.5)
			(island_removal_mode 0)
		)
		(polygon
			(pts
				(xy 14.560042 -273.61642) (xy 14.560042 -273.172682) (xy 16.885158 -273.172682) (xy 16.885158 -273.61642)
			)
		)
	)
	(zone
		(layer "F.Cu")
		(hatch none 0.5)
		(connect_pads
			(clearance 0)
		)
		(min_thickness 0.25)
		(keepout
			(tracks allowed)
			(vias allowed)
			(pads allowed)
			(copperpour allowed)
			(footprints not_allowed)
		)
		(placement
			(enabled no)
			(sheetname "")
		)
		(fill
			(thermal_gap 0.5)
			(thermal_bridge_width 0.5)
			(island_removal_mode 0)
		)
		(polygon
			(pts
				(xy 130.48107 -363.21492) (xy 142.54861 -363.21492) (xy 142.54861 -348.836488) (xy 130.48107 -348.836488)
			)
		)
	)
	(zone
		(layer "F.Cu")
		(hatch none 0.5)
		(connect_pads
			(clearance 0)
		)
		(min_thickness 0.25)
		(keepout
			(tracks allowed)
			(vias allowed)
			(pads allowed)
			(copperpour allowed)
			(footprints not_allowed)
		)
		(placement
			(enabled no)
			(sheetname "")
		)
		(fill
			(thermal_gap 0.5)
			(thermal_bridge_width 0.5)
			(island_removal_mode 0)
		)
		(polygon
			(pts
				(xy 68.929758 -314.770008) (xy 154.92984 -314.770008) (xy 154.92984 -188.770006) (xy 68.929758 -188.770006)
			)
		)
	)
	(zone
		(layer "F.Cu")
		(hatch none 0.5)
		(connect_pads
			(clearance 0)
		)
		(min_thickness 0.25)
		(keepout
			(tracks allowed)
			(vias allowed)
			(pads allowed)
			(copperpour allowed)
			(footprints allowed)
		)
		(placement
			(enabled no)
			(sheetname "")
		)
		(fill
			(thermal_gap 0.5)
			(thermal_bridge_width 0.5)
			(island_removal_mode 0)
		)
		(polygon
			(pts
				(xy 71.84136 -40.152828) (xy 71.84136 -38.555168) (xy 73.63968 -38.555168) (xy 73.63968 -40.152828)
			)
		)
	)
	(zone
		(layer "F.Cu")
		(hatch none 0.5)
		(connect_pads
			(clearance 0)
		)
		(min_thickness 0.25)
		(keepout
			(tracks not_allowed)
			(vias allowed)
			(pads allowed)
			(copperpour not_allowed)
			(footprints allowed)
		)
		(placement
			(enabled no)
			(sheetname "")
		)
		(fill
			(thermal_gap 0.5)
			(thermal_bridge_width 0.5)
			(island_removal_mode 0)
		)
		(polygon
			(pts
				(xy 54.8513 -164.211508) (xy 54.948836 -164.211508) (xy 54.948836 -164.163248) (xy 55.64886 -164.163248)
				(xy 55.64886 -162.613848) (xy 55.192168 -162.613848) (xy 55.192168 -163.309554) (xy 55.352696 -163.309554)
				(xy 55.352696 -163.868354) (xy 54.946296 -163.868354) (xy 54.946296 -163.309554) (xy 55.166768 -163.309554)
				(xy 55.166768 -162.613848) (xy 55.039768 -162.613848) (xy 55.039768 -163.069524) (xy 54.54396 -163.069524)
				(xy 54.54396 -163.31184) (xy 54.65318 -163.31184) (xy 54.65318 -163.993068) (xy 54.8513 -163.993068)
			)
		)
	)
	(zone
		(layer "F.Cu")
		(hatch none 0.5)
		(connect_pads
			(clearance 0)
		)
		(min_thickness 0.25)
		(keepout
			(tracks allowed)
			(vias allowed)
			(pads allowed)
			(copperpour allowed)
			(footprints allowed)
		)
		(placement
			(enabled no)
			(sheetname "")
		)
		(fill
			(thermal_gap 0.5)
			(thermal_bridge_width 0.5)
			(island_removal_mode 0)
		)
		(polygon
			(pts
				(xy 383.8575 -216.868248) (xy 384.14452 -216.868248) (xy 384.175 -216.837768) (xy 384.175 -216.210388)
				(xy 384.08864 -216.124028) (xy 383.90068 -216.124028) (xy 383.82702 -216.197688) (xy 383.82702 -216.837768)
			)
		)
	)
	(zone
		(layer "F.Cu")
		(hatch none 0.5)
		(connect_pads
			(clearance 0)
		)
		(min_thickness 0.25)
		(keepout
			(tracks allowed)
			(vias allowed)
			(pads allowed)
			(copperpour allowed)
			(footprints allowed)
		)
		(placement
			(enabled no)
			(sheetname "")
		)
		(fill
			(thermal_gap 0.5)
			(thermal_bridge_width 0.5)
			(island_removal_mode 0)
		)
		(polygon
			(pts
				(xy 64.185292 -410.948886) (xy 64.185292 -406.105868) (xy 66.069718 -406.105868) (xy 66.069718 -410.948886)
			)
		)
	)
	(zone
		(layer "F.Cu")
		(hatch none 0.5)
		(connect_pads
			(clearance 0)
		)
		(min_thickness 0.25)
		(keepout
			(tracks allowed)
			(vias allowed)
			(pads allowed)
			(copperpour allowed)
			(footprints allowed)
		)
		(placement
			(enabled no)
			(sheetname "")
		)
		(fill
			(thermal_gap 0.5)
			(thermal_bridge_width 0.5)
			(island_removal_mode 0)
		)
		(polygon
			(pts
				(xy 311.84088 -285.516574) (xy 311.84088 -285.072836) (xy 314.12688 -285.072836) (xy 314.12688 -285.516574)
			)
		)
	)
	(zone
		(layer "F.Cu")
		(hatch none 0.5)
		(connect_pads
			(clearance 0)
		)
		(min_thickness 0.25)
		(keepout
			(tracks allowed)
			(vias allowed)
			(pads allowed)
			(copperpour allowed)
			(footprints allowed)
		)
		(placement
			(enabled no)
			(sheetname "")
		)
		(fill
			(thermal_gap 0.5)
			(thermal_bridge_width 0.5)
			(island_removal_mode 0)
		)
		(polygon
			(pts
				(xy 49.149 -343.019888) (xy 49.149 -339.92058) (xy 53.2765 -339.92058) (xy 53.2765 -343.019888)
			)
		)
	)
	(zone
		(layer "F.Cu")
		(hatch none 0.5)
		(connect_pads
			(clearance 0)
		)
		(min_thickness 0.25)
		(keepout
			(tracks allowed)
			(vias allowed)
			(pads allowed)
			(copperpour allowed)
			(footprints allowed)
		)
		(placement
			(enabled no)
			(sheetname "")
		)
		(fill
			(thermal_gap 0.5)
			(thermal_bridge_width 0.5)
			(island_removal_mode 0)
		)
		(polygon
			(pts
				(xy 415.318702 -276.90699) (xy 413.286702 -276.90699) (xy 413.286702 -276.904704) (xy 413.107886 -276.904704)
				(xy 412.91764 -276.904704) (xy 412.91764 -276.624288) (xy 412.7881 -276.624288) (xy 412.7881 -276.114764)
				(xy 412.999428 -276.114764) (xy 415.539682 -276.114764) (xy 415.846768 -276.114764) (xy 415.846768 -276.660356)
				(xy 415.846768 -276.90699) (xy 415.599372 -276.90699) (xy 415.501836 -276.90699) (xy 415.454846 -276.90699)
			)
		)
	)
	(zone
		(layer "F.Cu")
		(hatch none 0.5)
		(connect_pads
			(clearance 0)
		)
		(min_thickness 0.25)
		(keepout
			(tracks allowed)
			(vias allowed)
			(pads allowed)
			(copperpour allowed)
			(footprints allowed)
		)
		(placement
			(enabled no)
			(sheetname "")
		)
		(fill
			(thermal_gap 0.5)
			(thermal_bridge_width 0.5)
			(island_removal_mode 0)
		)
		(polygon
			(pts
				(xy 307.76291 -271.472914) (xy 310.088026 -271.472914) (xy 310.14924 -271.472914) (xy 310.14924 -272.39849)
				(xy 307.628544 -272.39849) (xy 307.628544 -271.472914)
			)
		)
	)
	(zone
		(layer "F.Cu")
		(hatch none 0.5)
		(connect_pads
			(clearance 0)
		)
		(min_thickness 0.25)
		(keepout
			(tracks allowed)
			(vias allowed)
			(pads allowed)
			(copperpour allowed)
			(footprints allowed)
		)
		(placement
			(enabled no)
			(sheetname "")
		)
		(fill
			(thermal_gap 0.5)
			(thermal_bridge_width 0.5)
			(island_removal_mode 0)
		)
		(polygon
			(pts
				(xy 336.38744 -216.032588) (xy 336.67446 -216.032588) (xy 336.70494 -216.002108) (xy 336.70494 -215.374728)
				(xy 336.61858 -215.288368) (xy 336.43062 -215.288368) (xy 336.35696 -215.362028) (xy 336.35696 -216.002108)
			)
		)
	)
	(zone
		(layer "F.Cu")
		(hatch none 0.5)
		(connect_pads
			(clearance 0)
		)
		(min_thickness 0.25)
		(keepout
			(tracks allowed)
			(vias allowed)
			(pads allowed)
			(copperpour allowed)
			(footprints allowed)
		)
		(placement
			(enabled no)
			(sheetname "")
		)
		(fill
			(thermal_gap 0.5)
			(thermal_bridge_width 0.5)
			(island_removal_mode 0)
		)
		(polygon
			(pts
				(xy 183.44388 -14.371828) (xy 183.44388 -10.980928) (xy 189.72022 -10.980928) (xy 189.72022 -14.371828)
			)
		)
	)
	(zone
		(layer "F.Cu")
		(hatch none 0.5)
		(connect_pads
			(clearance 0)
		)
		(min_thickness 0.25)
		(keepout
			(tracks allowed)
			(vias allowed)
			(pads allowed)
			(copperpour allowed)
			(footprints allowed)
		)
		(placement
			(enabled no)
			(sheetname "")
		)
		(fill
			(thermal_gap 0.5)
			(thermal_bridge_width 0.5)
			(island_removal_mode 0)
		)
		(polygon
			(pts
				(xy 311.84088 -207.316578) (xy 311.84088 -206.87284) (xy 314.17768 -206.87284) (xy 314.17768 -207.316578)
			)
		)
	)
	(zone
		(layer "F.Cu")
		(hatch none 0.5)
		(connect_pads
			(clearance 0)
		)
		(min_thickness 0.25)
		(keepout
			(tracks allowed)
			(vias allowed)
			(pads allowed)
			(copperpour allowed)
			(footprints allowed)
		)
		(placement
			(enabled no)
			(sheetname "")
		)
		(fill
			(thermal_gap 0.5)
			(thermal_bridge_width 0.5)
			(island_removal_mode 0)
		)
		(polygon
			(pts
				(xy 176.979326 -314.076334) (xy 179.011326 -314.076334) (xy 179.011326 -314.304934) (xy 176.979326 -314.304934)
				(xy 176.843182 -314.304934) (xy 176.796192 -314.304934) (xy 176.796192 -314.076334) (xy 176.843182 -314.076334)
			)
		)
	)
	(zone
		(layer "F.Cu")
		(hatch none 0.5)
		(connect_pads
			(clearance 0)
		)
		(min_thickness 0.25)
		(keepout
			(tracks allowed)
			(vias allowed)
			(pads allowed)
			(copperpour allowed)
			(footprints allowed)
		)
		(placement
			(enabled no)
			(sheetname "")
		)
		(fill
			(thermal_gap 0.5)
			(thermal_bridge_width 0.5)
			(island_removal_mode 0)
		)
		(polygon
			(pts
				(xy 409.831794 -284.55493) (xy 409.831794 -284.32633) (xy 411.863794 -284.32633) (xy 411.863794 -284.55493)
			)
		)
	)
	(zone
		(layer "F.Cu")
		(hatch none 0.5)
		(connect_pads
			(clearance 0)
		)
		(min_thickness 0.25)
		(keepout
			(tracks not_allowed)
			(vias allowed)
			(pads allowed)
			(copperpour not_allowed)
			(footprints allowed)
		)
		(placement
			(enabled no)
			(sheetname "")
		)
		(fill
			(thermal_gap 0.5)
			(thermal_bridge_width 0.5)
			(island_removal_mode 0)
		)
		(polygon
			(pts
				(xy 383.695702 -344.548968) (xy 383.938018 -344.548968) (xy 383.938018 -343.593928) (xy 383.695702 -343.593928)
			)
		)
	)
	(zone
		(layer "F.Cu")
		(hatch none 0.5)
		(connect_pads
			(clearance 0)
		)
		(min_thickness 0.25)
		(keepout
			(tracks allowed)
			(vias allowed)
			(pads allowed)
			(copperpour allowed)
			(footprints allowed)
		)
		(placement
			(enabled no)
			(sheetname "")
		)
		(fill
			(thermal_gap 0.5)
			(thermal_bridge_width 0.5)
			(island_removal_mode 0)
		)
		(polygon
			(pts
				(xy 274.143978 -203.916534) (xy 274.143978 -203.472796) (xy 276.469094 -203.472796) (xy 276.469094 -203.916534)
			)
		)
	)
	(zone
		(layer "F.Cu")
		(hatch none 0.5)
		(connect_pads
			(clearance 0)
		)
		(min_thickness 0.25)
		(keepout
			(tracks allowed)
			(vias allowed)
			(pads allowed)
			(copperpour allowed)
			(footprints allowed)
		)
		(placement
			(enabled no)
			(sheetname "")
		)
		(fill
			(thermal_gap 0.5)
			(thermal_bridge_width 0.5)
			(island_removal_mode 0)
		)
		(polygon
			(pts
				(xy 440.006994 -280.076402) (xy 442.038994 -280.076402) (xy 442.038994 -280.305002) (xy 440.006994 -280.305002)
				(xy 439.87085 -280.305002) (xy 439.82386 -280.305002) (xy 439.82386 -280.076402) (xy 439.87085 -280.076402)
			)
		)
	)
	(zone
		(layer "F.Cu")
		(hatch none 0.5)
		(connect_pads
			(clearance 0)
		)
		(min_thickness 0.25)
		(keepout
			(tracks allowed)
			(vias allowed)
			(pads allowed)
			(copperpour allowed)
			(footprints allowed)
		)
		(placement
			(enabled no)
			(sheetname "")
		)
		(fill
			(thermal_gap 0.5)
			(thermal_bridge_width 0.5)
			(island_removal_mode 0)
		)
		(polygon
			(pts
				(xy 277.58771 -315.266578) (xy 277.58771 -314.82284) (xy 279.912826 -314.82284) (xy 279.912826 -315.266578)
			)
		)
	)
	(zone
		(layer "F.Cu")
		(hatch none 0.5)
		(connect_pads
			(clearance 0)
		)
		(min_thickness 0.25)
		(keepout
			(tracks allowed)
			(vias allowed)
			(pads allowed)
			(copperpour allowed)
			(footprints allowed)
		)
		(placement
			(enabled no)
			(sheetname "")
		)
		(fill
			(thermal_gap 0.5)
			(thermal_bridge_width 0.5)
			(island_removal_mode 0)
		)
		(polygon
			(pts
				(xy 405.731726 -222.505016) (xy 405.731726 -222.276416) (xy 407.763726 -222.276416) (xy 407.763726 -222.505016)
			)
		)
	)
	(zone
		(layer "F.Cu")
		(hatch none 0.5)
		(connect_pads
			(clearance 0)
		)
		(min_thickness 0.25)
		(keepout
			(tracks allowed)
			(vias allowed)
			(pads allowed)
			(copperpour allowed)
			(footprints allowed)
		)
		(placement
			(enabled no)
			(sheetname "")
		)
		(fill
			(thermal_gap 0.5)
			(thermal_bridge_width 0.5)
			(island_removal_mode 0)
		)
		(polygon
			(pts
				(xy 424.919394 -285.176214) (xy 426.951394 -285.176214) (xy 426.951394 -285.404814) (xy 424.919394 -285.404814)
				(xy 424.788076 -285.404814) (xy 424.762168 -285.404814) (xy 424.762168 -285.176214) (xy 424.788076 -285.176214)
			)
		)
	)
	(zone
		(layer "F.Cu")
		(hatch none 0.5)
		(connect_pads
			(clearance 0)
		)
		(min_thickness 0.25)
		(keepout
			(tracks allowed)
			(vias allowed)
			(pads allowed)
			(copperpour allowed)
			(footprints allowed)
		)
		(placement
			(enabled no)
			(sheetname "")
		)
		(fill
			(thermal_gap 0.5)
			(thermal_bridge_width 0.5)
			(island_removal_mode 0)
		)
		(polygon
			(pts
				(xy 165.335458 -208.90484) (xy 165.335458 -208.67624) (xy 167.367458 -208.67624) (xy 167.367458 -208.90484)
			)
		)
	)
	(zone
		(layer "F.Cu")
		(hatch none 0.5)
		(connect_pads
			(clearance 0)
		)
		(min_thickness 0.25)
		(keepout
			(tracks allowed)
			(vias allowed)
			(pads allowed)
			(copperpour allowed)
			(footprints not_allowed)
		)
		(placement
			(enabled no)
			(sheetname "")
		)
		(fill
			(thermal_gap 0.5)
			(thermal_bridge_width 0.5)
			(island_removal_mode 0)
		)
		(polygon
			(pts
				(xy 300.34357 -330.091796) (xy 306.44338 -330.091796) (xy 306.44338 -186.09183) (xy 300.34357 -186.09183)
			)
		)
	)
	(zone
		(layer "F.Cu")
		(hatch none 0.5)
		(connect_pads
			(clearance 0)
		)
		(min_thickness 0.25)
		(keepout
			(tracks allowed)
			(vias allowed)
			(pads allowed)
			(copperpour allowed)
			(footprints allowed)
		)
		(placement
			(enabled no)
			(sheetname "")
		)
		(fill
			(thermal_gap 0.5)
			(thermal_bridge_width 0.5)
			(island_removal_mode 0)
		)
		(polygon
			(pts
				(xy 165.335458 -226.754944) (xy 165.335458 -226.526344) (xy 167.367458 -226.526344) (xy 167.367458 -226.754944)
			)
		)
	)
	(zone
		(layer "F.Cu")
		(hatch none 0.5)
		(connect_pads
			(clearance 0)
		)
		(min_thickness 0.25)
		(keepout
			(tracks allowed)
			(vias allowed)
			(pads allowed)
			(copperpour allowed)
			(footprints allowed)
		)
		(placement
			(enabled no)
			(sheetname "")
		)
		(fill
			(thermal_gap 0.5)
			(thermal_bridge_width 0.5)
			(island_removal_mode 0)
		)
		(polygon
			(pts
				(xy 381.501904 -410.948886) (xy 381.501904 -406.105868) (xy 383.38633 -406.105868) (xy 383.38633 -410.948886)
			)
		)
	)
	(zone
		(layer "F.Cu")
		(hatch none 0.5)
		(connect_pads
			(clearance 0)
		)
		(min_thickness 0.25)
		(keepout
			(tracks allowed)
			(vias allowed)
			(pads allowed)
			(copperpour allowed)
			(footprints allowed)
		)
		(placement
			(enabled no)
			(sheetname "")
		)
		(fill
			(thermal_gap 0.5)
			(thermal_bridge_width 0.5)
			(island_removal_mode 0)
		)
		(polygon
			(pts
				(xy 138.26236 -220.909388) (xy 138.54938 -220.909388) (xy 138.57986 -220.878908) (xy 138.57986 -220.251528)
				(xy 138.4935 -220.165168) (xy 138.30554 -220.165168) (xy 138.23188 -220.238828) (xy 138.23188 -220.878908)
			)
		)
	)
	(zone
		(layer "F.Cu")
		(hatch none 0.5)
		(connect_pads
			(clearance 0)
		)
		(min_thickness 0.25)
		(keepout
			(tracks allowed)
			(vias allowed)
			(pads allowed)
			(copperpour allowed)
			(footprints allowed)
		)
		(placement
			(enabled no)
			(sheetname "")
		)
		(fill
			(thermal_gap 0.5)
			(thermal_bridge_width 0.5)
			(island_removal_mode 0)
		)
		(polygon
			(pts
				(xy 87.581486 -290.103814) (xy 107.647994 -290.10356) (xy 107.647994 -290.060126) (xy 111.257334 -290.060126)
				(xy 111.257334 -290.10356) (xy 137.791952 -290.103052) (xy 138.848592 -289.046412) (xy 138.848592 -280.788872)
				(xy 138.43381 -280.37409) (xy 137.740644 -280.37409) (xy 136.373108 -279.006554) (xy 136.372854 -275.18995)
				(xy 135.907272 -274.724368) (xy 135.907272 -253.718314) (xy 135.642604 -253.453646) (xy 135.203692 -253.014734)
				(xy 133.88213 -253.014734) (xy 133.196838 -252.329442) (xy 132.04317 -251.175774) (xy 132.04317 -248.675398)
				(xy 132.871464 -247.847104) (xy 134.903464 -247.847104) (xy 135.810498 -246.94007) (xy 135.80999 -227.200206)
				(xy 137.807192 -225.203004) (xy 138.998706 -225.203004) (xy 139.20089 -225.00082) (xy 139.20089 -218.525344)
				(xy 138.870182 -218.194636) (xy 138.869928 -215.543638) (xy 136.569196 -213.242906) (xy 111.256064 -213.243414)
				(xy 107.646724 -213.243414) (xy 88.935306 -213.243668) (xy 86.747858 -215.431116) (xy 86.509352 -215.669622)
				(xy 85.557106 -215.669622) (xy 85.413088 -215.813386) (xy 85.413342 -217.634312) (xy 86.439248 -218.660218)
				(xy 86.824058 -218.660218) (xy 87.879428 -219.715588) (xy 87.879428 -222.477076) (xy 87.415878 -222.940626)
				(xy 85.048852 -222.940626) (xy 84.39785 -223.591628) (xy 84.39785 -227.398072) (xy 84.969858 -227.97008)
				(xy 86.389972 -227.97008) (xy 87.962994 -229.543102) (xy 87.963502 -250.594114) (xy 86.893654 -251.663962)
				(xy 86.893654 -253.868682) (xy 88.017858 -254.992886) (xy 88.018112 -268.515084) (xy 87.051642 -269.481554)
				(xy 87.051642 -270.280638) (xy 87.505794 -270.73479) (xy 87.505794 -271.091152) (xy 88.00338 -271.588738)
				(xy 88.00338 -273.424904) (xy 86.50224 -274.926044) (xy 86.50224 -275.3995) (xy 86.916768 -275.813774)
				(xy 87.938102 -275.813774) (xy 89.101422 -276.977094) (xy 89.663524 -276.977094) (xy 90.42781 -277.74138)
				(xy 90.42781 -278.160734) (xy 90.250264 -278.33828) (xy 88.605868 -278.33828) (xy 88.459818 -278.48433)
				(xy 88.459818 -278.849582) (xy 88.075262 -279.234138) (xy 87.752174 -279.234138) (xy 87.20963 -279.234138)
				(xy 87.101172 -279.342596) (xy 86.57844 -279.342596) (xy 86.460076 -279.224232) (xy 86.20379 -279.224232)
				(xy 86.105238 -279.322784) (xy 86.105238 -279.659334) (xy 85.635338 -280.129234) (xy 85.635338 -281.52852)
				(xy 85.101938 -282.06192) (xy 85.101938 -287.62452)
			)
		)
	)
	(zone
		(layer "F.Cu")
		(hatch none 0.5)
		(connect_pads
			(clearance 0)
		)
		(min_thickness 0.25)
		(keepout
			(tracks allowed)
			(vias allowed)
			(pads allowed)
			(copperpour allowed)
			(footprints allowed)
		)
		(placement
			(enabled no)
			(sheetname "")
		)
		(fill
			(thermal_gap 0.5)
			(thermal_bridge_width 0.5)
			(island_removal_mode 0)
		)
		(polygon
			(pts
				(xy 409.831794 -282.005024) (xy 409.831794 -281.776424) (xy 411.863794 -281.776424) (xy 411.863794 -282.005024)
			)
		)
	)
	(zone
		(layer "F.Cu")
		(hatch none 0.5)
		(connect_pads
			(clearance 0)
		)
		(min_thickness 0.25)
		(keepout
			(tracks allowed)
			(vias allowed)
			(pads allowed)
			(copperpour allowed)
			(footprints not_allowed)
		)
		(placement
			(enabled no)
			(sheetname "")
		)
		(fill
			(thermal_gap 0.5)
			(thermal_bridge_width 0.5)
			(island_removal_mode 0)
		)
		(polygon
			(pts
				(arc
					(start 92.782898 -45.449998)
					(mid 91.182952 -47.049944)
					(end 92.782898 -48.64989)
				)
				(arc
					(start 94.383098 -48.64989)
					(mid 95.983044 -47.049944)
					(end 94.383098 -45.449998)
				)
			)
		)
	)
	(zone
		(layer "F.Cu")
		(hatch none 0.5)
		(connect_pads
			(clearance 0)
		)
		(min_thickness 0.25)
		(keepout
			(tracks allowed)
			(vias allowed)
			(pads allowed)
			(copperpour allowed)
			(footprints allowed)
		)
		(placement
			(enabled no)
			(sheetname "")
		)
		(fill
			(thermal_gap 0.5)
			(thermal_bridge_width 0.5)
			(island_removal_mode 0)
		)
		(polygon
			(pts
				(xy 14.560042 -262.566658) (xy 14.560042 -262.12292) (xy 16.885158 -262.12292) (xy 16.885158 -262.566658)
			)
		)
	)
	(zone
		(layer "F.Cu")
		(hatch none 0.5)
		(connect_pads
			(clearance 0)
		)
		(min_thickness 0.25)
		(keepout
			(tracks allowed)
			(vias allowed)
			(pads allowed)
			(copperpour allowed)
			(footprints allowed)
		)
		(placement
			(enabled no)
			(sheetname "")
		)
		(fill
			(thermal_gap 0.5)
			(thermal_bridge_width 0.5)
			(island_removal_mode 0)
		)
		(polygon
			(pts
				(xy 405.731726 -199.554846) (xy 405.731726 -199.326246) (xy 407.763726 -199.326246) (xy 407.763726 -199.554846)
			)
		)
	)
	(zone
		(layer "F.Cu")
		(hatch none 0.5)
		(connect_pads
			(clearance 0)
		)
		(min_thickness 0.25)
		(keepout
			(tracks allowed)
			(vias allowed)
			(pads allowed)
			(copperpour allowed)
			(footprints not_allowed)
		)
		(placement
			(enabled no)
			(sheetname "")
		)
		(fill
			(thermal_gap 0.5)
			(thermal_bridge_width 0.5)
			(island_removal_mode 0)
		)
		(polygon
			(pts
				(xy 309.93969 -438.989978) (xy 309.93969 -446.989962) (xy 298.939712 -446.989962) (xy 298.939712 -438.989978)
			)
		)
	)
	(zone
		(layer "F.Cu")
		(hatch none 0.5)
		(connect_pads
			(clearance 0)
		)
		(min_thickness 0.25)
		(keepout
			(tracks allowed)
			(vias allowed)
			(pads allowed)
			(copperpour allowed)
			(footprints allowed)
		)
		(placement
			(enabled no)
			(sheetname "")
		)
		(fill
			(thermal_gap 0.5)
			(thermal_bridge_width 0.5)
			(island_removal_mode 0)
		)
		(polygon
			(pts
				(xy 277.58771 -211.566506) (xy 277.58771 -211.122768) (xy 279.912826 -211.122768) (xy 279.912826 -211.566506)
			)
		)
	)
	(zone
		(layer "F.Cu")
		(hatch none 0.5)
		(connect_pads
			(clearance 0)
		)
		(min_thickness 0.25)
		(keepout
			(tracks allowed)
			(vias allowed)
			(pads allowed)
			(copperpour allowed)
			(footprints allowed)
		)
		(placement
			(enabled no)
			(sheetname "")
		)
		(fill
			(thermal_gap 0.5)
			(thermal_bridge_width 0.5)
			(island_removal_mode 0)
		)
		(polygon
			(pts
				(xy 210.598258 -252.25502) (xy 210.598258 -252.02642) (xy 212.630258 -252.02642) (xy 212.630258 -252.25502)
			)
		)
	)
	(zone
		(layer "F.Cu")
		(hatch none 0.5)
		(connect_pads
			(clearance 0)
		)
		(min_thickness 0.25)
		(keepout
			(tracks allowed)
			(vias allowed)
			(pads allowed)
			(copperpour allowed)
			(footprints not_allowed)
		)
		(placement
			(enabled no)
			(sheetname "")
		)
		(fill
			(thermal_gap 0.5)
			(thermal_bridge_width 0.5)
			(island_removal_mode 0)
		)
		(polygon
			(pts
				(xy 287.660334 -438.989978) (xy 287.660334 -446.989962) (xy 276.660356 -446.989962) (xy 276.660356 -438.989978)
			)
		)
	)
	(zone
		(layer "F.Cu")
		(hatch none 0.5)
		(connect_pads
			(clearance 0)
		)
		(min_thickness 0.25)
		(keepout
			(tracks allowed)
			(vias allowed)
			(pads allowed)
			(copperpour allowed)
			(footprints allowed)
		)
		(placement
			(enabled no)
			(sheetname "")
		)
		(fill
			(thermal_gap 0.5)
			(thermal_bridge_width 0.5)
			(island_removal_mode 0)
		)
		(polygon
			(pts
				(xy 413.275526 -213.155022) (xy 413.275526 -212.926422) (xy 415.307526 -212.926422) (xy 415.307526 -213.155022)
			)
		)
	)
	(zone
		(layer "F.Cu")
		(hatch none 0.5)
		(connect_pads
			(clearance 0)
		)
		(min_thickness 0.25)
		(keepout
			(tracks allowed)
			(vias allowed)
			(pads allowed)
			(copperpour allowed)
			(footprints allowed)
		)
		(placement
			(enabled no)
			(sheetname "")
		)
		(fill
			(thermal_gap 0.5)
			(thermal_bridge_width 0.5)
			(island_removal_mode 0)
		)
		(polygon
			(pts
				(xy 159.520128 -404.802594) (xy 159.520128 -399.959576) (xy 161.404554 -399.959576) (xy 161.404554 -404.802594)
			)
		)
	)
	(zone
		(layer "F.Cu")
		(hatch none 0.5)
		(connect_pads
			(clearance 0)
		)
		(min_thickness 0.25)
		(keepout
			(tracks allowed)
			(vias allowed)
			(pads allowed)
			(copperpour allowed)
			(footprints allowed)
		)
		(placement
			(enabled no)
			(sheetname "")
		)
		(fill
			(thermal_gap 0.5)
			(thermal_bridge_width 0.5)
			(island_removal_mode 0)
		)
		(polygon
			(pts
				(xy 304.34788 -267.66647) (xy 304.34788 -267.222732) (xy 306.60848 -267.222732) (xy 306.60848 -267.66647)
			)
		)
	)
	(zone
		(layer "F.Cu")
		(hatch none 0.5)
		(connect_pads
			(clearance 0)
		)
		(min_thickness 0.25)
		(keepout
			(tracks allowed)
			(vias allowed)
			(pads allowed)
			(copperpour allowed)
			(footprints not_allowed)
		)
		(placement
			(enabled no)
			(sheetname "")
		)
		(fill
			(thermal_gap 0.5)
			(thermal_bridge_width 0.5)
			(island_removal_mode 0)
		)
		(polygon
			(pts
				(xy 180.444902 -330.091796) (xy 186.544712 -330.091796) (xy 186.544712 -186.09183) (xy 180.444902 -186.09183)
			)
		)
	)
	(zone
		(layer "F.Cu")
		(hatch none 0.5)
		(connect_pads
			(clearance 0)
		)
		(min_thickness 0.25)
		(keepout
			(tracks allowed)
			(vias allowed)
			(pads allowed)
			(copperpour allowed)
			(footprints allowed)
		)
		(placement
			(enabled no)
			(sheetname "")
		)
		(fill
			(thermal_gap 0.5)
			(thermal_bridge_width 0.5)
			(island_removal_mode 0)
		)
		(polygon
			(pts
				(xy 292.67531 -305.066446) (xy 292.67531 -304.622708) (xy 295.000426 -304.622708) (xy 295.000426 -305.066446)
			)
		)
	)
	(zone
		(layer "F.Cu")
		(hatch none 0.5)
		(connect_pads
			(clearance 0)
		)
		(min_thickness 0.25)
		(keepout
			(tracks allowed)
			(vias allowed)
			(pads allowed)
			(copperpour allowed)
			(footprints allowed)
		)
		(placement
			(enabled no)
			(sheetname "")
		)
		(fill
			(thermal_gap 0.5)
			(thermal_bridge_width 0.5)
			(island_removal_mode 0)
		)
		(polygon
			(pts
				(xy 139.423648 -410.948886) (xy 139.423648 -406.105868) (xy 141.308074 -406.105868) (xy 141.308074 -410.948886)
			)
		)
	)
	(zone
		(layer "F.Cu")
		(hatch none 0.5)
		(connect_pads
			(clearance 0)
		)
		(min_thickness 0.25)
		(keepout
			(tracks allowed)
			(vias allowed)
			(pads allowed)
			(copperpour allowed)
			(footprints not_allowed)
		)
		(placement
			(enabled no)
			(sheetname "")
		)
		(fill
			(thermal_gap 0.5)
			(thermal_bridge_width 0.5)
			(island_removal_mode 0)
		)
		(polygon
			(pts
				(xy 467.300056 -166.236904)
				(arc
					(start 467.300056 -165.967664)
					(mid 467.169435 -166.103842)
					(end 467.035642 -166.236904)
				)
			)
		)
	)
	(zone
		(layer "F.Cu")
		(hatch none 0.5)
		(connect_pads
			(clearance 0)
		)
		(min_thickness 0.25)
		(keepout
			(tracks allowed)
			(vias allowed)
			(pads allowed)
			(copperpour allowed)
			(footprints allowed)
		)
		(placement
			(enabled no)
			(sheetname "")
		)
		(fill
			(thermal_gap 0.5)
			(thermal_bridge_width 0.5)
			(island_removal_mode 0)
		)
		(polygon
			(pts
				(xy 311.89168 -294.01643) (xy 311.89168 -293.572692) (xy 314.17768 -293.572692) (xy 314.17768 -294.01643)
			)
		)
	)
	(zone
		(layer "F.Cu")
		(hatch none 0.5)
		(connect_pads
			(clearance 0)
		)
		(min_thickness 0.25)
		(keepout
			(tracks allowed)
			(vias allowed)
			(pads allowed)
			(copperpour allowed)
			(footprints allowed)
		)
		(placement
			(enabled no)
			(sheetname "")
		)
		(fill
			(thermal_gap 0.5)
			(thermal_bridge_width 0.5)
			(island_removal_mode 0)
		)
		(polygon
			(pts
				(xy 44.735242 -287.216596) (xy 44.735242 -286.772858) (xy 47.060358 -286.772858) (xy 47.060358 -287.216596)
			)
		)
	)
	(zone
		(layer "F.Cu")
		(hatch none 0.5)
		(connect_pads
			(clearance 0)
		)
		(min_thickness 0.25)
		(keepout
			(tracks allowed)
			(vias allowed)
			(pads allowed)
			(copperpour allowed)
			(footprints allowed)
		)
		(placement
			(enabled no)
			(sheetname "")
		)
		(fill
			(thermal_gap 0.5)
			(thermal_bridge_width 0.5)
			(island_removal_mode 0)
		)
		(polygon
			(pts
				(xy 262.50011 -234.516422) (xy 262.50011 -234.072684) (xy 264.825226 -234.072684) (xy 264.825226 -234.516422)
			)
		)
	)
	(zone
		(layer "F.Cu")
		(hatch none 0.5)
		(connect_pads
			(clearance 0)
		)
		(min_thickness 0.25)
		(keepout
			(tracks allowed)
			(vias allowed)
			(pads allowed)
			(copperpour allowed)
			(footprints not_allowed)
		)
		(placement
			(enabled no)
			(sheetname "")
		)
		(fill
			(thermal_gap 0.5)
			(thermal_bridge_width 0.5)
			(island_removal_mode 0)
		)
		(polygon
			(pts
				(arc
					(start 165.1 -160.50006)
					(mid 167.900096 -157.699964)
					(end 170.699938 -160.50006)
				)
				(arc
					(start 170.699938 -160.50006)
					(mid 167.900096 -163.299902)
					(end 165.1 -160.50006)
				)
			)
		)
	)
	(zone
		(layer "F.Cu")
		(hatch none 0.5)
		(connect_pads
			(clearance 0)
		)
		(min_thickness 0.25)
		(keepout
			(tracks allowed)
			(vias allowed)
			(pads allowed)
			(copperpour allowed)
			(footprints allowed)
		)
		(placement
			(enabled no)
			(sheetname "")
		)
		(fill
			(thermal_gap 0.5)
			(thermal_bridge_width 0.5)
			(island_removal_mode 0)
		)
		(polygon
			(pts
				(xy 225.54438 -396.466568) (xy 225.54438 -393.189968) (xy 228.94544 -393.189968) (xy 228.94544 -396.466568)
			)
		)
	)
	(zone
		(layer "F.Cu")
		(hatch none 0.5)
		(connect_pads
			(clearance 0)
		)
		(min_thickness 0.25)
		(keepout
			(tracks allowed)
			(vias allowed)
			(pads allowed)
			(copperpour allowed)
			(footprints not_allowed)
		)
		(placement
			(enabled no)
			(sheetname "")
		)
		(fill
			(thermal_gap 0.5)
			(thermal_bridge_width 0.5)
			(island_removal_mode 0)
		)
		(polygon
			(pts
				(xy -2.794 -182.236872) (xy 7.20598 -182.236872) (xy 7.20598 -166.236904) (xy -2.794 -166.236904)
			)
		)
	)
	(zone
		(layer "F.Cu")
		(hatch none 0.5)
		(connect_pads
			(clearance 0)
		)
		(min_thickness 0.25)
		(keepout
			(tracks not_allowed)
			(vias allowed)
			(pads allowed)
			(copperpour not_allowed)
			(footprints allowed)
		)
		(placement
			(enabled no)
			(sheetname "")
		)
		(fill
			(thermal_gap 0.5)
			(thermal_bridge_width 0.5)
			(island_removal_mode 0)
		)
		(polygon
			(pts
				(arc
					(start 209.674968 -360.764074)
					(mid 213.67496 -356.764082)
					(end 217.674952 -360.764074)
				)
				(arc
					(start 217.674952 -360.764074)
					(mid 213.67496 -364.764066)
					(end 209.674968 -360.764074)
				)
			)
		)
	)
	(zone
		(layer "F.Cu")
		(hatch none 0.5)
		(connect_pads
			(clearance 0)
		)
		(min_thickness 0.25)
		(keepout
			(tracks allowed)
			(vias allowed)
			(pads allowed)
			(copperpour allowed)
			(footprints allowed)
		)
		(placement
			(enabled no)
			(sheetname "")
		)
		(fill
			(thermal_gap 0.5)
			(thermal_bridge_width 0.5)
			(island_removal_mode 0)
		)
		(polygon
			(pts
				(xy 424.919394 -258.826254) (xy 426.951394 -258.826254) (xy 426.951394 -259.054854) (xy 424.919394 -259.054854)
				(xy 424.743626 -259.054854) (xy 424.743626 -258.826254)
			)
		)
	)
	(zone
		(layer "F.Cu")
		(hatch none 0.5)
		(connect_pads
			(clearance 0)
		)
		(min_thickness 0.25)
		(keepout
			(tracks not_allowed)
			(vias allowed)
			(pads allowed)
			(copperpour not_allowed)
			(footprints allowed)
		)
		(placement
			(enabled no)
			(sheetname "")
		)
		(fill
			(thermal_gap 0.5)
			(thermal_bridge_width 0.5)
			(island_removal_mode 0)
		)
		(polygon
			(pts
				(arc
					(start 105.50017 -435.59984)
					(mid 100.50018 -440.59983)
					(end 95.50019 -435.59984)
				)
				(arc
					(start 95.50019 -435.59984)
					(mid 100.50018 -430.59985)
					(end 105.50017 -435.59984)
				)
			)
		)
	)
	(zone
		(layer "F.Cu")
		(hatch none 0.5)
		(connect_pads
			(clearance 0)
		)
		(min_thickness 0.25)
		(keepout
			(tracks allowed)
			(vias allowed)
			(pads allowed)
			(copperpour allowed)
			(footprints allowed)
		)
		(placement
			(enabled no)
			(sheetname "")
		)
		(fill
			(thermal_gap 0.5)
			(thermal_bridge_width 0.5)
			(island_removal_mode 0)
		)
		(polygon
			(pts
				(xy 167.378634 -274.35683) (xy 165.346634 -274.35683) (xy 165.346634 -274.354544) (xy 165.167818 -274.354544)
				(xy 164.977572 -274.354544) (xy 164.977572 -274.074128) (xy 164.848032 -274.074128) (xy 164.848032 -273.564604)
				(xy 165.05936 -273.564604) (xy 167.599614 -273.564604) (xy 167.9067 -273.564604) (xy 167.9067 -274.065746)
				(xy 167.786812 -274.065746) (xy 167.786812 -274.35683) (xy 167.73017 -274.35683) (xy 167.685212 -274.35683)
				(xy 167.659304 -274.35683) (xy 167.561768 -274.35683) (xy 167.514778 -274.35683)
			)
		)
	)
	(zone
		(layer "F.Cu")
		(hatch none 0.5)
		(connect_pads
			(clearance 0)
		)
		(min_thickness 0.25)
		(keepout
			(tracks allowed)
			(vias allowed)
			(pads allowed)
			(copperpour allowed)
			(footprints allowed)
		)
		(placement
			(enabled no)
			(sheetname "")
		)
		(fill
			(thermal_gap 0.5)
			(thermal_bridge_width 0.5)
			(island_removal_mode 0)
		)
		(polygon
			(pts
				(xy 292.67531 -196.266562) (xy 292.67531 -195.822824) (xy 295.000426 -195.822824) (xy 295.000426 -196.266562)
			)
		)
	)
	(zone
		(layer "F.Cu")
		(hatch none 0.5)
		(connect_pads
			(clearance 0)
		)
		(min_thickness 0.25)
		(keepout
			(tracks allowed)
			(vias allowed)
			(pads allowed)
			(copperpour allowed)
			(footprints allowed)
		)
		(placement
			(enabled no)
			(sheetname "")
		)
		(fill
			(thermal_gap 0.5)
			(thermal_bridge_width 0.5)
			(island_removal_mode 0)
		)
		(polygon
			(pts
				(xy 26.20391 -259.166614) (xy 26.20391 -258.722876) (xy 28.529026 -258.722876) (xy 28.529026 -259.166614)
			)
		)
	)
	(zone
		(layer "F.Cu")
		(hatch none 0.5)
		(connect_pads
			(clearance 0)
		)
		(min_thickness 0.25)
		(keepout
			(tracks allowed)
			(vias allowed)
			(pads allowed)
			(copperpour allowed)
			(footprints allowed)
		)
		(placement
			(enabled no)
			(sheetname "")
		)
		(fill
			(thermal_gap 0.5)
			(thermal_bridge_width 0.5)
			(island_removal_mode 0)
		)
		(polygon
			(pts
				(xy 176.979326 -275.206968) (xy 179.011326 -275.206968) (xy 179.011326 -274.978368) (xy 176.979326 -274.978368)
				(xy 176.848008 -274.978368) (xy 176.8221 -274.978368) (xy 176.8221 -275.206968) (xy 176.848008 -275.206968)
			)
		)
	)
	(zone
		(layer "F.Cu")
		(hatch none 0.5)
		(connect_pads
			(clearance 0)
		)
		(min_thickness 0.25)
		(keepout
			(tracks allowed)
			(vias allowed)
			(pads allowed)
			(copperpour allowed)
			(footprints allowed)
		)
		(placement
			(enabled no)
			(sheetname "")
		)
		(fill
			(thermal_gap 0.5)
			(thermal_bridge_width 0.5)
			(island_removal_mode 0)
		)
		(polygon
			(pts
				(xy 266.449556 -319.243456) (xy 266.449556 -316.881256) (xy 269.065756 -316.881256) (xy 269.065756 -319.243456)
			)
		)
	)
	(zone
		(layer "F.Cu")
		(hatch none 0.5)
		(connect_pads
			(clearance 0)
		)
		(min_thickness 0.25)
		(keepout
			(tracks allowed)
			(vias allowed)
			(pads allowed)
			(copperpour allowed)
			(footprints allowed)
		)
		(placement
			(enabled no)
			(sheetname "")
		)
		(fill
			(thermal_gap 0.5)
			(thermal_bridge_width 0.5)
			(island_removal_mode 0)
		)
		(polygon
			(pts
				(xy 192.066926 -276.676358) (xy 194.098926 -276.676358) (xy 194.098926 -276.678644) (xy 194.277742 -276.678644)
				(xy 194.277742 -276.91588) (xy 194.415664 -276.91588) (xy 194.458844 -276.95906) (xy 194.458844 -277.091902)
				(xy 194.458844 -277.39594) (xy 194.3862 -277.468584) (xy 191.845946 -277.468584) (xy 191.704722 -277.32736)
				(xy 191.704722 -277.130256) (xy 191.786256 -277.048722) (xy 191.786256 -276.676358) (xy 191.883792 -276.676358)
				(xy 191.930782 -276.676358)
			)
		)
	)
	(zone
		(layer "F.Cu")
		(hatch none 0.5)
		(connect_pads
			(clearance 0)
		)
		(min_thickness 0.25)
		(keepout
			(tracks allowed)
			(vias allowed)
			(pads allowed)
			(copperpour allowed)
			(footprints allowed)
		)
		(placement
			(enabled no)
			(sheetname "")
		)
		(fill
			(thermal_gap 0.5)
			(thermal_bridge_width 0.5)
			(island_removal_mode 0)
		)
		(polygon
			(pts
				(xy 86.21268 -218.435428) (xy 86.4997 -218.435428) (xy 86.53018 -218.404948) (xy 86.53018 -217.777568)
				(xy 86.44382 -217.691208) (xy 86.25586 -217.691208) (xy 86.1822 -217.764868) (xy 86.1822 -218.404948)
			)
		)
	)
	(zone
		(layer "F.Cu")
		(hatch none 0.5)
		(connect_pads
			(clearance 0)
		)
		(min_thickness 0.25)
		(keepout
			(tracks allowed)
			(vias allowed)
			(pads allowed)
			(copperpour allowed)
			(footprints allowed)
		)
		(placement
			(enabled no)
			(sheetname "")
		)
		(fill
			(thermal_gap 0.5)
			(thermal_bridge_width 0.5)
			(island_removal_mode 0)
		)
		(polygon
			(pts
				(xy 34.615882 -20.10791) (xy 34.615882 -16.973296) (xy 36.394644 -16.973296) (xy 36.394644 -20.10791)
			)
		)
	)
	(zone
		(layer "F.Cu")
		(hatch none 0.5)
		(connect_pads
			(clearance 0)
		)
		(min_thickness 0.25)
		(keepout
			(tracks allowed)
			(vias allowed)
			(pads allowed)
			(copperpour allowed)
			(footprints allowed)
		)
		(placement
			(enabled no)
			(sheetname "")
		)
		(fill
			(thermal_gap 0.5)
			(thermal_bridge_width 0.5)
			(island_removal_mode 0)
		)
		(polygon
			(pts
				(xy 56.37911 -213.266528) (xy 56.37911 -212.82279) (xy 58.704226 -212.82279) (xy 58.704226 -213.266528)
			)
		)
	)
	(zone
		(layer "F.Cu")
		(hatch none 0.5)
		(connect_pads
			(clearance 0)
		)
		(min_thickness 0.25)
		(keepout
			(tracks allowed)
			(vias allowed)
			(pads allowed)
			(copperpour allowed)
			(footprints allowed)
		)
		(placement
			(enabled no)
			(sheetname "")
		)
		(fill
			(thermal_gap 0.5)
			(thermal_bridge_width 0.5)
			(island_removal_mode 0)
		)
		(polygon
			(pts
				(xy 56.37911 -265.966448) (xy 56.37911 -265.52271) (xy 58.704226 -265.52271) (xy 58.704226 -265.966448)
			)
		)
	)
	(zone
		(layer "F.Cu")
		(hatch none 0.5)
		(connect_pads
			(clearance 0)
		)
		(min_thickness 0.25)
		(keepout
			(tracks allowed)
			(vias allowed)
			(pads allowed)
			(copperpour allowed)
			(footprints allowed)
		)
		(placement
			(enabled no)
			(sheetname "")
		)
		(fill
			(thermal_gap 0.5)
			(thermal_bridge_width 0.5)
			(island_removal_mode 0)
		)
		(polygon
			(pts
				(xy 424.919394 -266.476226) (xy 426.951394 -266.476226) (xy 426.951394 -266.704826) (xy 424.919394 -266.704826)
				(xy 424.75277 -266.704826) (xy 424.75277 -266.476226)
			)
		)
	)
	(zone
		(layer "F.Cu")
		(hatch none 0.5)
		(connect_pads
			(clearance 0)
		)
		(min_thickness 0.25)
		(keepout
			(tracks allowed)
			(vias allowed)
			(pads allowed)
			(copperpour allowed)
			(footprints allowed)
		)
		(placement
			(enabled no)
			(sheetname "")
		)
		(fill
			(thermal_gap 0.5)
			(thermal_bridge_width 0.5)
			(island_removal_mode 0)
		)
		(polygon
			(pts
				(xy 424.919394 -276.676358) (xy 426.951394 -276.676358) (xy 426.951394 -276.904958) (xy 424.919394 -276.904958)
				(xy 424.78325 -276.904958) (xy 424.73626 -276.904958) (xy 424.73626 -276.676358) (xy 424.78325 -276.676358)
			)
		)
	)
	(zone
		(layer "F.Cu")
		(hatch none 0.5)
		(connect_pads
			(clearance 0)
		)
		(min_thickness 0.25)
		(keepout
			(tracks allowed)
			(vias allowed)
			(pads allowed)
			(copperpour allowed)
			(footprints allowed)
		)
		(placement
			(enabled no)
			(sheetname "")
		)
		(fill
			(thermal_gap 0.5)
			(thermal_bridge_width 0.5)
			(island_removal_mode 0)
		)
		(polygon
			(pts
				(xy 180.423058 -252.25502) (xy 180.423058 -252.02642) (xy 182.455058 -252.02642) (xy 182.455058 -252.25502)
			)
		)
	)
	(zone
		(layer "F.Cu")
		(hatch none 0.5)
		(connect_pads
			(clearance 0)
		)
		(min_thickness 0.25)
		(keepout
			(tracks allowed)
			(vias allowed)
			(pads allowed)
			(copperpour allowed)
			(footprints allowed)
		)
		(placement
			(enabled no)
			(sheetname "")
		)
		(fill
			(thermal_gap 0.5)
			(thermal_bridge_width 0.5)
			(island_removal_mode 0)
		)
		(polygon
			(pts
				(xy 130.233928 -410.948886) (xy 130.233928 -406.105868) (xy 132.118354 -406.105868) (xy 132.118354 -410.948886)
			)
		)
	)
	(zone
		(layer "F.Cu")
		(hatch none 0.5)
		(connect_pads
			(clearance 0)
		)
		(min_thickness 0.25)
		(keepout
			(tracks allowed)
			(vias allowed)
			(pads allowed)
			(copperpour allowed)
			(footprints allowed)
		)
		(placement
			(enabled no)
			(sheetname "")
		)
		(fill
			(thermal_gap 0.5)
			(thermal_bridge_width 0.5)
			(island_removal_mode 0)
		)
		(polygon
			(pts
				(xy 428.363126 -225.904806) (xy 428.363126 -225.676206) (xy 430.395126 -225.676206) (xy 430.395126 -225.904806)
			)
		)
	)
	(zone
		(layer "F.Cu")
		(hatch none 0.5)
		(connect_pads
			(clearance 0)
		)
		(min_thickness 0.25)
		(keepout
			(tracks allowed)
			(vias allowed)
			(pads allowed)
			(copperpour allowed)
			(footprints allowed)
		)
		(placement
			(enabled no)
			(sheetname "")
		)
		(fill
			(thermal_gap 0.5)
			(thermal_bridge_width 0.5)
			(island_removal_mode 0)
		)
		(polygon
			(pts
				(xy 84.931758 -265.785346) (xy 85.134704 -265.5824) (xy 85.134704 -265.53922) (xy 84.690966 -265.095482)
				(xy 84.568792 -265.095482) (xy 84.43595 -265.228578) (xy 84.43595 -265.332718) (xy 84.888578 -265.785346)
			)
		)
	)
	(zone
		(layer "F.Cu")
		(hatch none 0.5)
		(connect_pads
			(clearance 0)
		)
		(min_thickness 0.25)
		(keepout
			(tracks not_allowed)
			(vias allowed)
			(pads allowed)
			(copperpour not_allowed)
			(footprints allowed)
		)
		(placement
			(enabled no)
			(sheetname "")
		)
		(fill
			(thermal_gap 0.5)
			(thermal_bridge_width 0.5)
			(island_removal_mode 0)
		)
		(polygon
			(pts
				(xy 299.25772 -413.83712) (xy 299.25772 -412.74746) (xy 299.4406 -412.74746) (xy 299.4406 -413.83712)
			)
		)
	)
	(zone
		(layer "F.Cu")
		(hatch none 0.5)
		(connect_pads
			(clearance 0)
		)
		(min_thickness 0.25)
		(keepout
			(tracks allowed)
			(vias allowed)
			(pads allowed)
			(copperpour allowed)
			(footprints allowed)
		)
		(placement
			(enabled no)
			(sheetname "")
		)
		(fill
			(thermal_gap 0.5)
			(thermal_bridge_width 0.5)
			(island_removal_mode 0)
		)
		(polygon
			(pts
				(xy 424.919394 -314.076334) (xy 426.951394 -314.076334) (xy 426.951394 -314.304934) (xy 424.919394 -314.304934)
				(xy 424.78325 -314.304934) (xy 424.73626 -314.304934) (xy 424.73626 -314.076334) (xy 424.78325 -314.076334)
			)
		)
	)
	(zone
		(layer "F.Cu")
		(hatch none 0.5)
		(connect_pads
			(clearance 0)
		)
		(min_thickness 0.25)
		(keepout
			(tracks allowed)
			(vias allowed)
			(pads allowed)
			(copperpour allowed)
			(footprints allowed)
		)
		(placement
			(enabled no)
			(sheetname "")
		)
		(fill
			(thermal_gap 0.5)
			(thermal_bridge_width 0.5)
			(island_removal_mode 0)
		)
		(polygon
			(pts
				(xy 56.37911 -312.716418) (xy 56.37911 -312.27268) (xy 58.704226 -312.27268) (xy 58.704226 -312.716418)
			)
		)
	)
	(zone
		(layer "F.Cu")
		(hatch none 0.5)
		(connect_pads
			(clearance 0)
		)
		(min_thickness 0.25)
		(keepout
			(tracks allowed)
			(vias allowed)
			(pads allowed)
			(copperpour allowed)
			(footprints allowed)
		)
		(placement
			(enabled no)
			(sheetname "")
		)
		(fill
			(thermal_gap 0.5)
			(thermal_bridge_width 0.5)
			(island_removal_mode 0)
		)
		(polygon
			(pts
				(xy 443.450726 -245.454932) (xy 443.450726 -245.226332) (xy 445.482726 -245.226332) (xy 445.482726 -245.454932)
			)
		)
	)
	(zone
		(layer "F.Cu")
		(hatch none 0.5)
		(connect_pads
			(clearance 0)
		)
		(min_thickness 0.25)
		(keepout
			(tracks allowed)
			(vias allowed)
			(pads allowed)
			(copperpour allowed)
			(footprints allowed)
		)
		(placement
			(enabled no)
			(sheetname "")
		)
		(fill
			(thermal_gap 0.5)
			(thermal_bridge_width 0.5)
			(island_removal_mode 0)
		)
		(polygon
			(pts
				(xy 443.450726 -197.854824) (xy 443.450726 -197.626224) (xy 445.482726 -197.626224) (xy 445.482726 -197.854824)
			)
		)
	)
	(zone
		(layer "F.Cu")
		(hatch none 0.5)
		(connect_pads
			(clearance 0)
		)
		(min_thickness 0.25)
		(keepout
			(tracks allowed)
			(vias allowed)
			(pads allowed)
			(copperpour allowed)
			(footprints allowed)
		)
		(placement
			(enabled no)
			(sheetname "")
		)
		(fill
			(thermal_gap 0.5)
			(thermal_bridge_width 0.5)
			(island_removal_mode 0)
		)
		(polygon
			(pts
				(xy 274.143978 -305.066446) (xy 274.143978 -304.622708) (xy 276.469094 -304.622708) (xy 276.469094 -305.066446)
			)
		)
	)
	(zone
		(layer "F.Cu")
		(hatch none 0.5)
		(connect_pads
			(clearance 0)
		)
		(min_thickness 0.25)
		(keepout
			(tracks allowed)
			(vias allowed)
			(pads allowed)
			(copperpour allowed)
			(footprints allowed)
		)
		(placement
			(enabled no)
			(sheetname "")
		)
		(fill
			(thermal_gap 0.5)
			(thermal_bridge_width 0.5)
			(island_removal_mode 0)
		)
		(polygon
			(pts
				(xy 412.64332 -9.677908) (xy 412.64332 -5.888228) (xy 420.58336 -5.888228) (xy 420.58336 -9.677908)
			)
		)
	)
	(zone
		(layer "F.Cu")
		(hatch none 0.5)
		(connect_pads
			(clearance 0)
		)
		(min_thickness 0.25)
		(keepout
			(tracks allowed)
			(vias allowed)
			(pads allowed)
			(copperpour allowed)
			(footprints allowed)
		)
		(placement
			(enabled no)
			(sheetname "")
		)
		(fill
			(thermal_gap 0.5)
			(thermal_bridge_width 0.5)
			(island_removal_mode 0)
		)
		(polygon
			(pts
				(xy 86.300818 -253.644146) (xy 86.503764 -253.4412) (xy 86.503764 -253.39802) (xy 86.060026 -252.954282)
				(xy 85.937852 -252.954282) (xy 85.80501 -253.087378) (xy 85.80501 -253.191518) (xy 86.257638 -253.644146)
			)
		)
	)
	(zone
		(layer "F.Cu")
		(hatch none 0.5)
		(connect_pads
			(clearance 0)
		)
		(min_thickness 0.25)
		(keepout
			(tracks allowed)
			(vias allowed)
			(pads allowed)
			(copperpour allowed)
			(footprints not_allowed)
		)
		(placement
			(enabled no)
			(sheetname "")
		)
		(fill
			(thermal_gap 0.5)
			(thermal_bridge_width 0.5)
			(island_removal_mode 0)
		)
		(polygon
			(pts
				(xy 324.39991 -61.449966) (xy 349.400114 -61.449966) (xy 349.400114 -35.450018) (xy 324.39991 -35.450018)
			)
		)
	)
	(zone
		(layer "F.Cu")
		(hatch none 0.5)
		(connect_pads
			(clearance 0)
		)
		(min_thickness 0.25)
		(keepout
			(tracks allowed)
			(vias allowed)
			(pads allowed)
			(copperpour allowed)
			(footprints not_allowed)
		)
		(placement
			(enabled no)
			(sheetname "")
		)
		(fill
			(thermal_gap 0.5)
			(thermal_bridge_width 0.5)
			(island_removal_mode 0)
		)
		(polygon
			(pts
				(xy 29.772102 -330.091796) (xy 35.871912 -330.091796) (xy 35.871912 -186.09183) (xy 29.772102 -186.09183)
			)
		)
	)
	(zone
		(layer "F.Cu")
		(hatch none 0.5)
		(connect_pads
			(clearance 0)
		)
		(min_thickness 0.25)
		(keepout
			(tracks allowed)
			(vias allowed)
			(pads allowed)
			(copperpour allowed)
			(footprints allowed)
		)
		(placement
			(enabled no)
			(sheetname "")
		)
		(fill
			(thermal_gap 0.5)
			(thermal_bridge_width 0.5)
			(island_removal_mode 0)
		)
		(polygon
			(pts
				(xy 14.560042 -230.266494) (xy 14.560042 -229.822756) (xy 16.885158 -229.822756) (xy 16.885158 -230.266494)
			)
		)
	)
	(zone
		(layer "F.Cu")
		(hatch none 0.5)
		(connect_pads
			(clearance 0)
		)
		(min_thickness 0.25)
		(keepout
			(tracks allowed)
			(vias allowed)
			(pads allowed)
			(copperpour allowed)
			(footprints allowed)
		)
		(placement
			(enabled no)
			(sheetname "")
		)
		(fill
			(thermal_gap 0.5)
			(thermal_bridge_width 0.5)
			(island_removal_mode 0)
		)
		(polygon
			(pts
				(xy 428.363126 -291.355018) (xy 428.363126 -291.126418) (xy 430.395126 -291.126418) (xy 430.395126 -291.355018)
			)
		)
	)
	(zone
		(layer "F.Cu")
		(hatch none 0.5)
		(connect_pads
			(clearance 0)
		)
		(min_thickness 0.25)
		(keepout
			(tracks allowed)
			(vias allowed)
			(pads allowed)
			(copperpour allowed)
			(footprints allowed)
		)
		(placement
			(enabled no)
			(sheetname "")
		)
		(fill
			(thermal_gap 0.5)
			(thermal_bridge_width 0.5)
			(island_removal_mode 0)
		)
		(polygon
			(pts
				(xy 26.20391 -202.216512) (xy 26.20391 -201.772774) (xy 28.529026 -201.772774) (xy 28.529026 -202.216512)
			)
		)
	)
	(zone
		(layer "F.Cu")
		(hatch none 0.5)
		(connect_pads
			(clearance 0)
		)
		(min_thickness 0.25)
		(keepout
			(tracks allowed)
			(vias allowed)
			(pads allowed)
			(copperpour allowed)
			(footprints allowed)
		)
		(placement
			(enabled no)
			(sheetname "")
		)
		(fill
			(thermal_gap 0.5)
			(thermal_bridge_width 0.5)
			(island_removal_mode 0)
		)
		(polygon
			(pts
				(xy 56.37911 -196.266562) (xy 56.37911 -195.822824) (xy 58.704226 -195.822824) (xy 58.704226 -196.266562)
			)
		)
	)
	(zone
		(layer "F.Cu")
		(hatch none 0.5)
		(connect_pads
			(clearance 0)
		)
		(min_thickness 0.25)
		(keepout
			(tracks allowed)
			(vias allowed)
			(pads allowed)
			(copperpour allowed)
			(footprints allowed)
		)
		(placement
			(enabled no)
			(sheetname "")
		)
		(fill
			(thermal_gap 0.5)
			(thermal_bridge_width 0.5)
			(island_removal_mode 0)
		)
		(polygon
			(pts
				(xy 289.231578 -219.216478) (xy 289.231578 -218.77274) (xy 291.556694 -218.77274) (xy 291.556694 -219.216478)
			)
		)
	)
	(zone
		(layer "F.Cu")
		(hatch none 0.5)
		(connect_pads
			(clearance 0)
		)
		(min_thickness 0.25)
		(keepout
			(tracks allowed)
			(vias allowed)
			(pads allowed)
			(copperpour allowed)
			(footprints allowed)
		)
		(placement
			(enabled no)
			(sheetname "")
		)
		(fill
			(thermal_gap 0.5)
			(thermal_bridge_width 0.5)
			(island_removal_mode 0)
		)
		(polygon
			(pts
				(xy 262.50011 -268.516608) (xy 262.50011 -268.07287) (xy 264.825226 -268.07287) (xy 264.825226 -268.516608)
			)
		)
	)
	(zone
		(layer "F.Cu")
		(hatch none 0.5)
		(connect_pads
			(clearance 0)
		)
		(min_thickness 0.25)
		(keepout
			(tracks allowed)
			(vias allowed)
			(pads allowed)
			(copperpour allowed)
			(footprints allowed)
		)
		(placement
			(enabled no)
			(sheetname "")
		)
		(fill
			(thermal_gap 0.5)
			(thermal_bridge_width 0.5)
			(island_removal_mode 0)
		)
		(polygon
			(pts
				(xy 56.37911 -303.366424) (xy 56.37911 -302.922686) (xy 58.704226 -302.922686) (xy 58.704226 -303.366424)
			)
		)
	)
	(zone
		(layer "F.Cu")
		(hatch none 0.5)
		(connect_pads
			(clearance 0)
		)
		(min_thickness 0.25)
		(keepout
			(tracks allowed)
			(vias allowed)
			(pads allowed)
			(copperpour allowed)
			(footprints allowed)
		)
		(placement
			(enabled no)
			(sheetname "")
		)
		(fill
			(thermal_gap 0.5)
			(thermal_bridge_width 0.5)
			(island_removal_mode 0)
		)
		(polygon
			(pts
				(xy 274.143978 -226.016566) (xy 274.143978 -225.572828) (xy 276.469094 -225.572828) (xy 276.469094 -226.016566)
			)
		)
	)
	(zone
		(layer "F.Cu")
		(hatch none 0.5)
		(connect_pads
			(clearance 0)
		)
		(min_thickness 0.25)
		(keepout
			(tracks allowed)
			(vias allowed)
			(pads allowed)
			(copperpour allowed)
			(footprints allowed)
		)
		(placement
			(enabled no)
			(sheetname "")
		)
		(fill
			(thermal_gap 0.5)
			(thermal_bridge_width 0.5)
			(island_removal_mode 0)
		)
		(polygon
			(pts
				(xy 192.066926 -264.776204) (xy 194.098926 -264.776204) (xy 194.098926 -265.004804) (xy 192.066926 -265.004804)
				(xy 191.900302 -265.004804) (xy 191.778636 -265.004804) (xy 191.778636 -264.776204) (xy 191.900302 -264.776204)
			)
		)
	)
	(zone
		(layer "F.Cu")
		(hatch none 0.5)
		(connect_pads
			(clearance 0)
		)
		(min_thickness 0.25)
		(keepout
			(tracks allowed)
			(vias allowed)
			(pads allowed)
			(copperpour allowed)
			(footprints allowed)
		)
		(placement
			(enabled no)
			(sheetname "")
		)
		(fill
			(thermal_gap 0.5)
			(thermal_bridge_width 0.5)
			(island_removal_mode 0)
		)
		(polygon
			(pts
				(xy 424.919394 -308.126384) (xy 426.951394 -308.126384) (xy 426.951394 -308.354984) (xy 424.919394 -308.354984)
				(xy 424.78325 -308.354984) (xy 424.73626 -308.354984) (xy 424.73626 -308.126384) (xy 424.78325 -308.126384)
			)
		)
	)
	(zone
		(layer "F.Cu")
		(hatch none 0.5)
		(connect_pads
			(clearance 0)
		)
		(min_thickness 0.25)
		(keepout
			(tracks allowed)
			(vias allowed)
			(pads allowed)
			(copperpour allowed)
			(footprints allowed)
		)
		(placement
			(enabled no)
			(sheetname "")
		)
		(fill
			(thermal_gap 0.5)
			(thermal_bridge_width 0.5)
			(island_removal_mode 0)
		)
		(polygon
			(pts
				(xy 135.55218 -287.368488) (xy 135.8392 -287.368488) (xy 135.86968 -287.338008) (xy 135.86968 -286.710628)
				(xy 135.78332 -286.624268) (xy 135.59536 -286.624268) (xy 135.5217 -286.697928) (xy 135.5217 -287.338008)
			)
		)
	)
	(zone
		(layer "F.Cu")
		(hatch none 0.5)
		(connect_pads
			(clearance 0)
		)
		(min_thickness 0.25)
		(keepout
			(tracks allowed)
			(vias allowed)
			(pads allowed)
			(copperpour allowed)
			(footprints allowed)
		)
		(placement
			(enabled no)
			(sheetname "")
		)
		(fill
			(thermal_gap 0.5)
			(thermal_bridge_width 0.5)
			(island_removal_mode 0)
		)
		(polygon
			(pts
				(xy 41.29151 -264.266426) (xy 41.29151 -263.822688) (xy 43.616626 -263.822688) (xy 43.616626 -264.266426)
			)
		)
	)
	(zone
		(layer "F.Cu")
		(hatch none 0.5)
		(connect_pads
			(clearance 0)
		)
		(min_thickness 0.25)
		(keepout
			(tracks allowed)
			(vias allowed)
			(pads allowed)
			(copperpour allowed)
			(footprints allowed)
		)
		(placement
			(enabled no)
			(sheetname "")
		)
		(fill
			(thermal_gap 0.5)
			(thermal_bridge_width 0.5)
			(island_removal_mode 0)
		)
		(polygon
			(pts
				(xy 440.006994 -251.176282) (xy 442.038994 -251.176282) (xy 442.038994 -251.404882) (xy 440.006994 -251.404882)
				(xy 439.84037 -251.404882) (xy 439.84037 -251.176282)
			)
		)
	)
	(zone
		(layer "F.Cu")
		(hatch none 0.5)
		(connect_pads
			(clearance 0)
		)
		(min_thickness 0.25)
		(keepout
			(tracks allowed)
			(vias allowed)
			(pads allowed)
			(copperpour allowed)
			(footprints allowed)
		)
		(placement
			(enabled no)
			(sheetname "")
		)
		(fill
			(thermal_gap 0.5)
			(thermal_bridge_width 0.5)
			(island_removal_mode 0)
		)
		(polygon
			(pts
				(xy 56.37911 -284.666436) (xy 56.37911 -284.222698) (xy 58.704226 -284.222698) (xy 58.704226 -284.666436)
			)
		)
	)
	(zone
		(layer "F.Cu")
		(hatch none 0.5)
		(connect_pads
			(clearance 0)
		)
		(min_thickness 0.25)
		(keepout
			(tracks allowed)
			(vias allowed)
			(pads allowed)
			(copperpour allowed)
			(footprints allowed)
		)
		(placement
			(enabled no)
			(sheetname "")
		)
		(fill
			(thermal_gap 0.5)
			(thermal_bridge_width 0.5)
			(island_removal_mode 0)
		)
		(polygon
			(pts
				(xy 29.647642 -224.316544) (xy 29.647642 -223.872806) (xy 31.972758 -223.872806) (xy 31.972758 -224.316544)
			)
		)
	)
	(zone
		(layer "F.Cu")
		(hatch none 0.5)
		(connect_pads
			(clearance 0)
		)
		(min_thickness 0.25)
		(keepout
			(tracks allowed)
			(vias allowed)
			(pads allowed)
			(copperpour allowed)
			(footprints not_allowed)
		)
		(placement
			(enabled no)
			(sheetname "")
		)
		(fill
			(thermal_gap 0.5)
			(thermal_bridge_width 0.5)
			(island_removal_mode 0)
		)
		(polygon
			(pts
				(arc
					(start 368.498628 -435.600094)
					(mid 371.298724 -432.799998)
					(end 374.098566 -435.600094)
				)
				(arc
					(start 374.098566 -435.600094)
					(mid 371.298724 -438.399936)
					(end 368.498628 -435.600094)
				)
			)
		)
	)
	(zone
		(layer "F.Cu")
		(hatch none 0.5)
		(connect_pads
			(clearance 0)
		)
		(min_thickness 0.25)
		(keepout
			(tracks allowed)
			(vias allowed)
			(pads allowed)
			(copperpour allowed)
			(footprints allowed)
		)
		(placement
			(enabled no)
			(sheetname "")
		)
		(fill
			(thermal_gap 0.5)
			(thermal_bridge_width 0.5)
			(island_removal_mode 0)
		)
		(polygon
			(pts
				(xy 417.11753 -319.243202) (xy 417.11753 -317.52667) (xy 419.73373 -317.52667) (xy 419.73373 -319.243202)
				(xy 419.73373 -319.964308) (xy 417.11753 -319.964308) (xy 417.11753 -319.428114)
			)
		)
	)
	(zone
		(layer "F.Cu")
		(hatch none 0.5)
		(connect_pads
			(clearance 0)
		)
		(min_thickness 0.25)
		(keepout
			(tracks allowed)
			(vias allowed)
			(pads allowed)
			(copperpour allowed)
			(footprints allowed)
		)
		(placement
			(enabled no)
			(sheetname "")
		)
		(fill
			(thermal_gap 0.5)
			(thermal_bridge_width 0.5)
			(island_removal_mode 0)
		)
		(polygon
			(pts
				(xy 413.275526 -297.304968) (xy 413.275526 -297.076368) (xy 415.307526 -297.076368) (xy 415.307526 -297.304968)
			)
		)
	)
	(zone
		(layer "F.Cu")
		(hatch none 0.5)
		(connect_pads
			(clearance 0)
		)
		(min_thickness 0.25)
		(keepout
			(tracks allowed)
			(vias allowed)
			(pads allowed)
			(copperpour allowed)
			(footprints allowed)
		)
		(placement
			(enabled no)
			(sheetname "")
		)
		(fill
			(thermal_gap 0.5)
			(thermal_bridge_width 0.5)
			(island_removal_mode 0)
		)
		(polygon
			(pts
				(xy 426.951394 -269.026132) (xy 426.951394 -269.254732) (xy 426.951394 -269.700756) (xy 424.870626 -269.700756)
				(xy 424.870626 -268.423136) (xy 426.951394 -268.423136)
			)
		)
	)
	(zone
		(layer "F.Cu")
		(hatch none 0.5)
		(connect_pads
			(clearance 0)
		)
		(min_thickness 0.25)
		(keepout
			(tracks allowed)
			(vias allowed)
			(pads allowed)
			(copperpour allowed)
			(footprints allowed)
		)
		(placement
			(enabled no)
			(sheetname "")
		)
		(fill
			(thermal_gap 0.5)
			(thermal_bridge_width 0.5)
			(island_removal_mode 0)
		)
		(polygon
			(pts
				(xy 165.335458 -208.054956) (xy 165.335458 -207.826356) (xy 167.367458 -207.826356) (xy 167.367458 -208.054956)
			)
		)
	)
	(zone
		(layer "F.Cu")
		(hatch none 0.5)
		(connect_pads
			(clearance 0)
		)
		(min_thickness 0.25)
		(keepout
			(tracks allowed)
			(vias allowed)
			(pads allowed)
			(copperpour allowed)
			(footprints allowed)
		)
		(placement
			(enabled no)
			(sheetname "")
		)
		(fill
			(thermal_gap 0.5)
			(thermal_bridge_width 0.5)
			(island_removal_mode 0)
		)
		(polygon
			(pts
				(xy 59.822842 -280.416508) (xy 59.822842 -279.97277) (xy 62.147958 -279.97277) (xy 62.147958 -280.416508)
			)
		)
	)
	(zone
		(layer "F.Cu")
		(hatch none 0.5)
		(connect_pads
			(clearance 0)
		)
		(min_thickness 0.25)
		(keepout
			(tracks not_allowed)
			(vias allowed)
			(pads allowed)
			(copperpour not_allowed)
			(footprints allowed)
		)
		(placement
			(enabled no)
			(sheetname "")
		)
		(fill
			(thermal_gap 0.5)
			(thermal_bridge_width 0.5)
			(island_removal_mode 0)
		)
		(polygon
			(pts
				(xy 383.96672 -343.163398) (xy 384.39344 -343.163398) (xy 384.39344 -342.870282) (xy 383.935732 -342.870282)
				(xy 383.935732 -342.64981) (xy 383.240026 -342.64981) (xy 383.240026 -342.77681) (xy 383.695702 -342.77681)
				(xy 383.695702 -343.139268) (xy 383.96672 -343.139268)
			)
		)
	)
	(zone
		(layer "F.Cu")
		(hatch none 0.5)
		(connect_pads
			(clearance 0)
		)
		(min_thickness 0.25)
		(keepout
			(tracks allowed)
			(vias allowed)
			(pads allowed)
			(copperpour allowed)
			(footprints allowed)
		)
		(placement
			(enabled no)
			(sheetname "")
		)
		(fill
			(thermal_gap 0.5)
			(thermal_bridge_width 0.5)
			(island_removal_mode 0)
		)
		(polygon
			(pts
				(xy 12.099798 -104.287066) (xy 12.099798 -102.84968) (xy 13.701268 -102.84968) (xy 13.701268 -104.287066)
			)
		)
	)
	(zone
		(layer "F.Cu")
		(hatch none 0.5)
		(connect_pads
			(clearance 0)
		)
		(min_thickness 0.25)
		(keepout
			(tracks allowed)
			(vias allowed)
			(pads allowed)
			(copperpour allowed)
			(footprints allowed)
		)
		(placement
			(enabled no)
			(sheetname "")
		)
		(fill
			(thermal_gap 0.5)
			(thermal_bridge_width 0.5)
			(island_removal_mode 0)
		)
		(polygon
			(pts
				(xy 398.232122 -5.888228) (xy 398.232122 -3.952748) (xy 400.403822 -3.952748) (xy 400.403822 -5.888228)
			)
		)
	)
	(zone
		(layer "F.Cu")
		(hatch none 0.5)
		(connect_pads
			(clearance 0)
		)
		(min_thickness 0.25)
		(keepout
			(tracks allowed)
			(vias allowed)
			(pads allowed)
			(copperpour allowed)
			(footprints allowed)
		)
		(placement
			(enabled no)
			(sheetname "")
		)
		(fill
			(thermal_gap 0.5)
			(thermal_bridge_width 0.5)
			(island_removal_mode 0)
		)
		(polygon
			(pts
				(xy 259.056378 -276.16658) (xy 259.056378 -275.722842) (xy 261.381494 -275.722842) (xy 261.381494 -276.16658)
			)
		)
	)
	(zone
		(layer "F.Cu")
		(hatch none 0.5)
		(connect_pads
			(clearance 0)
		)
		(min_thickness 0.25)
		(keepout
			(tracks allowed)
			(vias allowed)
			(pads allowed)
			(copperpour allowed)
			(footprints allowed)
		)
		(placement
			(enabled no)
			(sheetname "")
		)
		(fill
			(thermal_gap 0.5)
			(thermal_bridge_width 0.5)
			(island_removal_mode 0)
		)
		(polygon
			(pts
				(xy 136.85266 -216.891108) (xy 137.13968 -216.891108) (xy 137.17016 -216.860628) (xy 137.17016 -216.233248)
				(xy 137.0838 -216.146888) (xy 136.89584 -216.146888) (xy 136.82218 -216.220548) (xy 136.82218 -216.860628)
			)
		)
	)
	(zone
		(layer "F.Cu")
		(hatch none 0.5)
		(connect_pads
			(clearance 0)
		)
		(min_thickness 0.25)
		(keepout
			(tracks allowed)
			(vias allowed)
			(pads allowed)
			(copperpour allowed)
			(footprints allowed)
		)
		(placement
			(enabled no)
			(sheetname "")
		)
		(fill
			(thermal_gap 0.5)
			(thermal_bridge_width 0.5)
			(island_removal_mode 0)
		)
		(polygon
			(pts
				(xy 62.147958 -271.066514) (xy 59.822842 -271.066514) (xy 59.69635 -271.066514) (xy 59.69635 -270.115538)
				(xy 62.217046 -270.115538) (xy 62.217046 -271.066514)
			)
		)
	)
	(zone
		(layer "F.Cu")
		(hatch none 0.5)
		(connect_pads
			(clearance 0)
		)
		(min_thickness 0.25)
		(keepout
			(tracks allowed)
			(vias allowed)
			(pads allowed)
			(copperpour allowed)
			(footprints allowed)
		)
		(placement
			(enabled no)
			(sheetname "")
		)
		(fill
			(thermal_gap 0.5)
			(thermal_bridge_width 0.5)
			(island_removal_mode 0)
		)
		(polygon
			(pts
				(xy 11.11631 -294.01643) (xy 11.11631 -293.572692) (xy 13.441426 -293.572692) (xy 13.441426 -294.01643)
			)
		)
	)
	(zone
		(layer "F.Cu")
		(hatch none 0.5)
		(connect_pads
			(clearance 0)
		)
		(min_thickness 0.25)
		(keepout
			(tracks allowed)
			(vias allowed)
			(pads allowed)
			(copperpour allowed)
			(footprints allowed)
		)
		(placement
			(enabled no)
			(sheetname "")
		)
		(fill
			(thermal_gap 0.5)
			(thermal_bridge_width 0.5)
			(island_removal_mode 0)
		)
		(polygon
			(pts
				(xy 210.598258 -304.95494) (xy 210.598258 -304.72634) (xy 212.630258 -304.72634) (xy 212.630258 -304.95494)
			)
		)
	)
	(zone
		(layer "F.Cu")
		(hatch none 0.5)
		(connect_pads
			(clearance 0)
		)
		(min_thickness 0.25)
		(keepout
			(tracks allowed)
			(vias allowed)
			(pads allowed)
			(copperpour allowed)
			(footprints allowed)
		)
		(placement
			(enabled no)
			(sheetname "")
		)
		(fill
			(thermal_gap 0.5)
			(thermal_bridge_width 0.5)
			(island_removal_mode 0)
		)
		(polygon
			(pts
				(xy 458.538326 -262.454898) (xy 458.538326 -262.226298) (xy 460.570326 -262.226298) (xy 460.570326 -262.454898)
			)
		)
	)
	(zone
		(layer "F.Cu")
		(hatch none 0.5)
		(connect_pads
			(clearance 0)
		)
		(min_thickness 0.25)
		(keepout
			(tracks allowed)
			(vias allowed)
			(pads allowed)
			(copperpour allowed)
			(footprints allowed)
		)
		(placement
			(enabled no)
			(sheetname "")
		)
		(fill
			(thermal_gap 0.5)
			(thermal_bridge_width 0.5)
			(island_removal_mode 0)
		)
		(polygon
			(pts
				(xy 307.76291 -202.216512) (xy 307.76291 -201.772774) (xy 310.088026 -201.772774) (xy 310.088026 -202.216512)
			)
		)
	)
	(zone
		(layer "F.Cu")
		(hatch none 0.5)
		(connect_pads
			(clearance 0)
		)
		(min_thickness 0.25)
		(keepout
			(tracks allowed)
			(vias allowed)
			(pads allowed)
			(copperpour allowed)
			(footprints allowed)
		)
		(placement
			(enabled no)
			(sheetname "")
		)
		(fill
			(thermal_gap 0.5)
			(thermal_bridge_width 0.5)
			(island_removal_mode 0)
		)
		(polygon
			(pts
				(xy 44.735242 -196.266562) (xy 44.735242 -195.822824) (xy 47.060358 -195.822824) (xy 47.060358 -196.266562)
			)
		)
	)
	(zone
		(layer "F.Cu")
		(hatch none 0.5)
		(connect_pads
			(clearance 0)
		)
		(min_thickness 0.25)
		(keepout
			(tracks allowed)
			(vias allowed)
			(pads allowed)
			(copperpour allowed)
			(footprints allowed)
		)
		(placement
			(enabled no)
			(sheetname "")
		)
		(fill
			(thermal_gap 0.5)
			(thermal_bridge_width 0.5)
			(island_removal_mode 0)
		)
		(polygon
			(pts
				(xy 424.919394 -294.526208) (xy 426.951394 -294.526208) (xy 426.951394 -294.754808) (xy 424.919394 -294.754808)
				(xy 424.788076 -294.754808) (xy 424.762168 -294.754808) (xy 424.762168 -294.526208) (xy 424.788076 -294.526208)
			)
		)
	)
	(zone
		(layer "F.Cu")
		(hatch none 0.5)
		(connect_pads
			(clearance 0)
		)
		(min_thickness 0.25)
		(keepout
			(tracks allowed)
			(vias allowed)
			(pads allowed)
			(copperpour allowed)
			(footprints allowed)
		)
		(placement
			(enabled no)
			(sheetname "")
		)
		(fill
			(thermal_gap 0.5)
			(thermal_bridge_width 0.5)
			(island_removal_mode 0)
		)
		(polygon
			(pts
				(xy 274.143978 -250.666504) (xy 274.143978 -250.222766) (xy 276.469094 -250.222766) (xy 276.469094 -250.666504)
			)
		)
	)
	(zone
		(layer "F.Cu")
		(hatch none 0.5)
		(connect_pads
			(clearance 0)
		)
		(min_thickness 0.25)
		(keepout
			(tracks allowed)
			(vias allowed)
			(pads allowed)
			(copperpour allowed)
			(footprints allowed)
		)
		(placement
			(enabled no)
			(sheetname "")
		)
		(fill
			(thermal_gap 0.5)
			(thermal_bridge_width 0.5)
			(island_removal_mode 0)
		)
		(polygon
			(pts
				(xy 29.647642 -234.072684) (xy 31.972758 -234.072684) (xy 32.045402 -234.072684) (xy 32.045402 -234.995212)
				(xy 29.50845 -234.995212) (xy 29.50845 -234.072684)
			)
		)
	)
	(zone
		(layer "F.Cu")
		(hatch none 0.5)
		(connect_pads
			(clearance 0)
		)
		(min_thickness 0.25)
		(keepout
			(tracks allowed)
			(vias allowed)
			(pads allowed)
			(copperpour allowed)
			(footprints allowed)
		)
		(placement
			(enabled no)
			(sheetname "")
		)
		(fill
			(thermal_gap 0.5)
			(thermal_bridge_width 0.5)
			(island_removal_mode 0)
		)
		(polygon
			(pts
				(xy 29.647642 -244.716554) (xy 29.647642 -244.272816) (xy 31.972758 -244.272816) (xy 31.972758 -244.716554)
			)
		)
	)
	(zone
		(layer "F.Cu")
		(hatch none 0.5)
		(connect_pads
			(clearance 0)
		)
		(min_thickness 0.25)
		(keepout
			(tracks allowed)
			(vias allowed)
			(pads allowed)
			(copperpour allowed)
			(footprints allowed)
		)
		(placement
			(enabled no)
			(sheetname "")
		)
		(fill
			(thermal_gap 0.5)
			(thermal_bridge_width 0.5)
			(island_removal_mode 0)
		)
		(polygon
			(pts
				(xy 292.67531 -197.116446) (xy 292.67531 -196.672708) (xy 295.000426 -196.672708) (xy 295.000426 -197.116446)
			)
		)
	)
	(zone
		(layer "F.Cu")
		(hatch none 0.5)
		(connect_pads
			(clearance 0)
		)
		(min_thickness 0.25)
		(keepout
			(tracks not_allowed)
			(vias allowed)
			(pads allowed)
			(copperpour not_allowed)
			(footprints allowed)
		)
		(placement
			(enabled no)
			(sheetname "")
		)
		(fill
			(thermal_gap 0.5)
			(thermal_bridge_width 0.5)
			(island_removal_mode 0)
		)
		(polygon
			(pts
				(arc
					(start 99.899978 -22.29993)
					(mid 94.899988 -27.29992)
					(end 89.899998 -22.29993)
				)
				(arc
					(start 89.899998 -22.29993)
					(mid 94.899988 -17.29994)
					(end 99.899978 -22.29993)
				)
			)
		)
	)
	(zone
		(layer "F.Cu")
		(hatch none 0.5)
		(connect_pads
			(clearance 0)
		)
		(min_thickness 0.25)
		(keepout
			(tracks allowed)
			(vias allowed)
			(pads allowed)
			(copperpour allowed)
			(footprints allowed)
		)
		(placement
			(enabled no)
			(sheetname "")
		)
		(fill
			(thermal_gap 0.5)
			(thermal_bridge_width 0.5)
			(island_removal_mode 0)
		)
		(polygon
			(pts
				(xy 88.13038 -288.285428) (xy 88.4174 -288.285428) (xy 88.44788 -288.254948) (xy 88.44788 -287.627568)
				(xy 88.36152 -287.541208) (xy 88.17356 -287.541208) (xy 88.0999 -287.614868) (xy 88.0999 -288.254948)
			)
		)
	)
	(zone
		(layer "F.Cu")
		(hatch none 0.5)
		(connect_pads
			(clearance 0)
		)
		(min_thickness 0.25)
		(keepout
			(tracks allowed)
			(vias allowed)
			(pads allowed)
			(copperpour allowed)
			(footprints allowed)
		)
		(placement
			(enabled no)
			(sheetname "")
		)
		(fill
			(thermal_gap 0.5)
			(thermal_bridge_width 0.5)
			(island_removal_mode 0)
		)
		(polygon
			(pts
				(xy 455.094594 -281.776424) (xy 457.126594 -281.776424) (xy 457.126594 -282.005024) (xy 455.094594 -282.005024)
				(xy 454.95845 -282.005024) (xy 454.91146 -282.005024) (xy 454.91146 -281.776424) (xy 454.95845 -281.776424)
			)
		)
	)
	(zone
		(layer "F.Cu")
		(hatch none 0.5)
		(connect_pads
			(clearance 0)
		)
		(min_thickness 0.25)
		(keepout
			(tracks allowed)
			(vias allowed)
			(pads allowed)
			(copperpour allowed)
			(footprints allowed)
		)
		(placement
			(enabled no)
			(sheetname "")
		)
		(fill
			(thermal_gap 0.5)
			(thermal_bridge_width 0.5)
			(island_removal_mode 0)
		)
		(polygon
			(pts
				(xy 108.204 -339.087968) (xy 108.204 -334.493108) (xy 115.0874 -334.493108) (xy 115.0874 -339.087968)
			)
		)
	)
	(zone
		(layer "F.Cu")
		(hatch none 0.5)
		(connect_pads
			(clearance 0)
		)
		(min_thickness 0.25)
		(keepout
			(tracks not_allowed)
			(vias allowed)
			(pads allowed)
			(copperpour not_allowed)
			(footprints allowed)
		)
		(placement
			(enabled no)
			(sheetname "")
		)
		(fill
			(thermal_gap 0.5)
			(thermal_bridge_width 0.5)
			(island_removal_mode 0)
		)
		(polygon
			(pts
				(arc
					(start 458.659992 -347.700092)
					(mid 461.460088 -344.899996)
					(end 464.25993 -347.700092)
				)
				(arc
					(start 464.25993 -347.700092)
					(mid 461.460088 -350.499934)
					(end 458.659992 -347.700092)
				)
			)
		)
	)
	(zone
		(layer "F.Cu")
		(hatch none 0.5)
		(connect_pads
			(clearance 0)
		)
		(min_thickness 0.25)
		(keepout
			(tracks allowed)
			(vias allowed)
			(pads allowed)
			(copperpour allowed)
			(footprints allowed)
		)
		(placement
			(enabled no)
			(sheetname "")
		)
		(fill
			(thermal_gap 0.5)
			(thermal_bridge_width 0.5)
			(island_removal_mode 0)
		)
		(polygon
			(pts
				(xy 48.720502 -351.521268) (xy 48.720502 -355.526848) (xy 49.200562 -356.006908) (xy 51.265582 -356.006908)
				(xy 51.537362 -355.735128) (xy 51.537362 -353.880928) (xy 51.788822 -353.629468) (xy 53.709062 -353.629468)
				(xy 54.125622 -353.212908) (xy 54.125622 -351.721928) (xy 53.477922 -351.074228) (xy 49.167542 -351.074228)
			)
		)
	)
	(zone
		(layer "F.Cu")
		(hatch none 0.5)
		(connect_pads
			(clearance 0)
		)
		(min_thickness 0.25)
		(keepout
			(tracks allowed)
			(vias allowed)
			(pads allowed)
			(copperpour allowed)
			(footprints allowed)
		)
		(placement
			(enabled no)
			(sheetname "")
		)
		(fill
			(thermal_gap 0.5)
			(thermal_bridge_width 0.5)
			(island_removal_mode 0)
		)
		(polygon
			(pts
				(xy 277.58771 -262.566658) (xy 277.58771 -262.12292) (xy 279.912826 -262.12292) (xy 279.912826 -262.566658)
			)
		)
	)
	(zone
		(layer "F.Cu")
		(hatch none 0.5)
		(connect_pads
			(clearance 0)
		)
		(min_thickness 0.25)
		(keepout
			(tracks allowed)
			(vias allowed)
			(pads allowed)
			(copperpour allowed)
			(footprints allowed)
		)
		(placement
			(enabled no)
			(sheetname "")
		)
		(fill
			(thermal_gap 0.5)
			(thermal_bridge_width 0.5)
			(island_removal_mode 0)
		)
		(polygon
			(pts
				(xy 161.891726 -249.70486) (xy 161.891726 -249.47626) (xy 163.923726 -249.47626) (xy 163.923726 -249.70486)
			)
		)
	)
	(zone
		(layer "F.Cu")
		(hatch none 0.5)
		(connect_pads
			(clearance 0)
		)
		(min_thickness 0.25)
		(keepout
			(tracks allowed)
			(vias allowed)
			(pads allowed)
			(copperpour allowed)
			(footprints allowed)
		)
		(placement
			(enabled no)
			(sheetname "")
		)
		(fill
			(thermal_gap 0.5)
			(thermal_bridge_width 0.5)
			(island_removal_mode 0)
		)
		(polygon
			(pts
				(xy 259.056378 -308.46649) (xy 259.056378 -308.022752) (xy 261.381494 -308.022752) (xy 261.381494 -308.46649)
			)
		)
	)
	(zone
		(layer "F.Cu")
		(hatch none 0.5)
		(connect_pads
			(clearance 0)
		)
		(min_thickness 0.25)
		(keepout
			(tracks allowed)
			(vias allowed)
			(pads allowed)
			(copperpour allowed)
			(footprints allowed)
		)
		(placement
			(enabled no)
			(sheetname "")
		)
		(fill
			(thermal_gap 0.5)
			(thermal_bridge_width 0.5)
			(island_removal_mode 0)
		)
		(polygon
			(pts
				(xy 86.53526 -217.635328) (xy 86.82228 -217.635328) (xy 86.85276 -217.604848) (xy 86.85276 -216.977468)
				(xy 86.7664 -216.891108) (xy 86.57844 -216.891108) (xy 86.50478 -216.964768) (xy 86.50478 -217.604848)
			)
		)
	)
	(zone
		(layer "F.Cu")
		(hatch none 0.5)
		(connect_pads
			(clearance 0)
		)
		(min_thickness 0.25)
		(keepout
			(tracks allowed)
			(vias allowed)
			(pads allowed)
			(copperpour allowed)
			(footprints allowed)
		)
		(placement
			(enabled no)
			(sheetname "")
		)
		(fill
			(thermal_gap 0.5)
			(thermal_bridge_width 0.5)
			(island_removal_mode 0)
		)
		(polygon
			(pts
				(xy 161.891726 -295.604946) (xy 161.891726 -295.376346) (xy 163.923726 -295.376346) (xy 163.923726 -295.604946)
			)
		)
	)
	(zone
		(layer "F.Cu")
		(hatch none 0.5)
		(connect_pads
			(clearance 0)
		)
		(min_thickness 0.25)
		(keepout
			(tracks not_allowed)
			(vias allowed)
			(pads allowed)
			(copperpour not_allowed)
			(footprints allowed)
		)
		(placement
			(enabled no)
			(sheetname "")
		)
		(fill
			(thermal_gap 0.5)
			(thermal_bridge_width 0.5)
			(island_removal_mode 0)
		)
		(polygon
			(pts
				(xy 418.07384 -155.11907) (xy 418.162486 -155.11907) (xy 418.162486 -154.663902) (xy 420.08044 -154.663902)
				(xy 420.08044 -154.487372) (xy 418.580824 -154.487372) (xy 418.580824 -153.711148) (xy 418.557964 -153.688288)
				(xy 418.28212 -153.688288) (xy 418.28212 -153.564844) (xy 417.66236 -153.564844) (xy 417.604956 -153.622248)
				(xy 417.604956 -155.11907) (xy 418.04844 -155.11907) (xy 418.04844 -154.422602) (xy 417.901882 -154.422602)
				(xy 417.901882 -153.965402) (xy 418.206682 -153.965402) (xy 418.206682 -154.422602) (xy 418.07384 -154.422602)
			)
		)
	)
	(zone
		(layer "F.Cu")
		(hatch none 0.5)
		(connect_pads
			(clearance 0)
		)
		(min_thickness 0.25)
		(keepout
			(tracks allowed)
			(vias allowed)
			(pads allowed)
			(copperpour allowed)
			(footprints allowed)
		)
		(placement
			(enabled no)
			(sheetname "")
		)
		(fill
			(thermal_gap 0.5)
			(thermal_bridge_width 0.5)
			(island_removal_mode 0)
		)
		(polygon
			(pts
				(xy 439.72734 -95.052388) (xy 439.72734 -93.182948) (xy 441.73902 -93.182948) (xy 441.73902 -95.052388)
			)
		)
	)
	(zone
		(layer "F.Cu")
		(hatch none 0.5)
		(connect_pads
			(clearance 0)
		)
		(min_thickness 0.25)
		(keepout
			(tracks allowed)
			(vias allowed)
			(pads allowed)
			(copperpour allowed)
			(footprints not_allowed)
		)
		(placement
			(enabled no)
			(sheetname "")
		)
		(fill
			(thermal_gap 0.5)
			(thermal_bridge_width 0.5)
			(island_removal_mode 0)
		)
		(polygon
			(pts
				(arc
					(start 1.999996 -22.29993)
					(mid 6.999986 -17.29994)
					(end 11.999976 -22.29993)
				)
				(arc
					(start 11.999976 -22.29993)
					(mid 6.999986 -27.29992)
					(end 1.999996 -22.29993)
				)
			)
		)
	)
	(zone
		(layer "F.Cu")
		(hatch none 0.5)
		(connect_pads
			(clearance 0)
		)
		(min_thickness 0.25)
		(keepout
			(tracks allowed)
			(vias allowed)
			(pads allowed)
			(copperpour allowed)
			(footprints allowed)
		)
		(placement
			(enabled no)
			(sheetname "")
		)
		(fill
			(thermal_gap 0.5)
			(thermal_bridge_width 0.5)
			(island_removal_mode 0)
		)
		(polygon
			(pts
				(xy 262.50011 -217.516456) (xy 262.50011 -217.072718) (xy 264.825226 -217.072718) (xy 264.825226 -217.516456)
			)
		)
	)
	(zone
		(layer "F.Cu")
		(hatch none 0.5)
		(connect_pads
			(clearance 0)
		)
		(min_thickness 0.25)
		(keepout
			(tracks allowed)
			(vias allowed)
			(pads allowed)
			(copperpour allowed)
			(footprints not_allowed)
		)
		(placement
			(enabled no)
			(sheetname "")
		)
		(fill
			(thermal_gap 0.5)
			(thermal_bridge_width 0.5)
			(island_removal_mode 0)
		)
		(polygon
			(pts
				(arc
					(start 18.91157 -440.989974)
					(mid 18.603422 -429.890528)
					(end 7.500112 -429.790606)
				)
				(arc
					(start 7.500112 -439.989976)
					(mid 7.793005 -440.697081)
					(end 8.50011 -440.989974)
				)
			)
		)
	)
	(zone
		(layer "F.Cu")
		(hatch none 0.5)
		(connect_pads
			(clearance 0)
		)
		(min_thickness 0.25)
		(keepout
			(tracks allowed)
			(vias allowed)
			(pads allowed)
			(copperpour allowed)
			(footprints allowed)
		)
		(placement
			(enabled no)
			(sheetname "")
		)
		(fill
			(thermal_gap 0.5)
			(thermal_bridge_width 0.5)
			(island_removal_mode 0)
		)
		(polygon
			(pts
				(xy 195.510658 -214.85479) (xy 195.510658 -214.62619) (xy 197.542658 -214.62619) (xy 197.542658 -214.85479)
			)
		)
	)
	(zone
		(layer "F.Cu")
		(hatch none 0.5)
		(connect_pads
			(clearance 0)
		)
		(min_thickness 0.25)
		(keepout
			(tracks allowed)
			(vias allowed)
			(pads allowed)
			(copperpour allowed)
			(footprints not_allowed)
		)
		(placement
			(enabled no)
			(sheetname "")
		)
		(fill
			(thermal_gap 0.5)
			(thermal_bridge_width 0.5)
			(island_removal_mode 0)
		)
		(polygon
			(pts
				(xy 401.646898 -43.344592) (xy 388.152894 -43.344592) (xy 388.152894 -70.65518) (xy 401.646898 -70.65518)
			)
		)
	)
	(zone
		(layer "F.Cu")
		(hatch none 0.5)
		(connect_pads
			(clearance 0)
		)
		(min_thickness 0.25)
		(keepout
			(tracks allowed)
			(vias allowed)
			(pads allowed)
			(copperpour allowed)
			(footprints allowed)
		)
		(placement
			(enabled no)
			(sheetname "")
		)
		(fill
			(thermal_gap 0.5)
			(thermal_bridge_width 0.5)
			(island_removal_mode 0)
		)
		(polygon
			(pts
				(xy 26.20391 -197.966584) (xy 26.20391 -197.522846) (xy 28.529026 -197.522846) (xy 28.529026 -197.966584)
			)
		)
	)
	(zone
		(layer "F.Cu")
		(hatch none 0.5)
		(connect_pads
			(clearance 0)
		)
		(min_thickness 0.25)
		(keepout
			(tracks allowed)
			(vias allowed)
			(pads allowed)
			(copperpour allowed)
			(footprints allowed)
		)
		(placement
			(enabled no)
			(sheetname "")
		)
		(fill
			(thermal_gap 0.5)
			(thermal_bridge_width 0.5)
			(island_removal_mode 0)
		)
		(polygon
			(pts
				(xy 424.919394 -263.076436) (xy 426.951394 -263.076436) (xy 426.951394 -263.305036) (xy 424.919394 -263.305036)
				(xy 424.75277 -263.305036) (xy 424.655234 -263.305036) (xy 424.655234 -263.076436) (xy 424.75277 -263.076436)
			)
		)
	)
	(zone
		(layer "F.Cu")
		(hatch none 0.5)
		(connect_pads
			(clearance 0)
		)
		(min_thickness 0.25)
		(keepout
			(tracks allowed)
			(vias allowed)
			(pads allowed)
			(copperpour allowed)
			(footprints allowed)
		)
		(placement
			(enabled no)
			(sheetname "")
		)
		(fill
			(thermal_gap 0.5)
			(thermal_bridge_width 0.5)
			(island_removal_mode 0)
		)
		(polygon
			(pts
				(xy 180.423058 -205.504796) (xy 180.423058 -205.276196) (xy 182.455058 -205.276196) (xy 182.455058 -205.504796)
			)
		)
	)
	(zone
		(layer "F.Cu")
		(hatch none 0.5)
		(connect_pads
			(clearance 0)
		)
		(min_thickness 0.25)
		(keepout
			(tracks allowed)
			(vias allowed)
			(pads allowed)
			(copperpour allowed)
			(footprints allowed)
		)
		(placement
			(enabled no)
			(sheetname "")
		)
		(fill
			(thermal_gap 0.5)
			(thermal_bridge_width 0.5)
			(island_removal_mode 0)
		)
		(polygon
			(pts
				(xy 274.143978 -278.272748) (xy 276.469094 -278.272748) (xy 276.534626 -278.272748) (xy 276.534626 -279.23617)
				(xy 274.009866 -279.23617) (xy 274.009866 -278.272748)
			)
		)
	)
	(zone
		(layer "F.Cu")
		(hatch none 0.5)
		(connect_pads
			(clearance 0)
		)
		(min_thickness 0.25)
		(keepout
			(tracks allowed)
			(vias allowed)
			(pads allowed)
			(copperpour allowed)
			(footprints allowed)
		)
		(placement
			(enabled no)
			(sheetname "")
		)
		(fill
			(thermal_gap 0.5)
			(thermal_bridge_width 0.5)
			(island_removal_mode 0)
		)
		(polygon
			(pts
				(xy 304.319178 -209.866484) (xy 304.319178 -209.422746) (xy 306.644294 -209.422746) (xy 306.644294 -209.866484)
			)
		)
	)
	(zone
		(layer "F.Cu")
		(hatch none 0.5)
		(connect_pads
			(clearance 0)
		)
		(min_thickness 0.25)
		(keepout
			(tracks allowed)
			(vias allowed)
			(pads allowed)
			(copperpour allowed)
			(footprints allowed)
		)
		(placement
			(enabled no)
			(sheetname "")
		)
		(fill
			(thermal_gap 0.5)
			(thermal_bridge_width 0.5)
			(island_removal_mode 0)
		)
		(polygon
			(pts
				(xy 416.152076 -364.330488) (xy 414.404556 -364.330488) (xy 414.404556 -362.395008) (xy 416.152076 -362.395008)
			)
		)
	)
	(zone
		(layer "F.Cu")
		(hatch none 0.5)
		(connect_pads
			(clearance 0)
		)
		(min_thickness 0.25)
		(keepout
			(tracks allowed)
			(vias allowed)
			(pads allowed)
			(copperpour allowed)
			(footprints allowed)
		)
		(placement
			(enabled no)
			(sheetname "")
		)
		(fill
			(thermal_gap 0.5)
			(thermal_bridge_width 0.5)
			(island_removal_mode 0)
		)
		(polygon
			(pts
				(xy 304.319178 -299.116496) (xy 304.319178 -298.672758) (xy 306.644294 -298.672758) (xy 306.644294 -299.116496)
			)
		)
	)
	(zone
		(layer "F.Cu")
		(hatch none 0.5)
		(connect_pads
			(clearance 0)
		)
		(min_thickness 0.25)
		(keepout
			(tracks allowed)
			(vias allowed)
			(pads allowed)
			(copperpour allowed)
			(footprints allowed)
		)
		(placement
			(enabled no)
			(sheetname "")
		)
		(fill
			(thermal_gap 0.5)
			(thermal_bridge_width 0.5)
			(island_removal_mode 0)
		)
		(polygon
			(pts
				(xy 62.147958 -235.36656) (xy 59.822842 -235.36656) (xy 59.684412 -235.36656) (xy 59.684412 -234.447334)
				(xy 62.213236 -234.447334) (xy 62.213236 -235.36656)
			)
		)
	)
	(zone
		(layer "F.Cu")
		(hatch none 0.5)
		(connect_pads
			(clearance 0)
		)
		(min_thickness 0.25)
		(keepout
			(tracks allowed)
			(vias allowed)
			(pads allowed)
			(copperpour allowed)
			(footprints not_allowed)
		)
		(placement
			(enabled no)
			(sheetname "")
		)
		(fill
			(thermal_gap 0.5)
			(thermal_bridge_width 0.5)
			(island_removal_mode 0)
		)
		(polygon
			(pts
				(arc
					(start 238.949992 -39.425118)
					(mid 239.94999 -38.42512)
					(end 240.949988 -39.425118)
				)
				(arc
					(start 240.949988 -39.425118)
					(mid 239.94999 -40.425116)
					(end 238.949992 -39.425118)
				)
			)
		)
	)
	(zone
		(layer "F.Cu")
		(hatch none 0.5)
		(connect_pads
			(clearance 0)
		)
		(min_thickness 0.25)
		(keepout
			(tracks allowed)
			(vias allowed)
			(pads allowed)
			(copperpour allowed)
			(footprints allowed)
		)
		(placement
			(enabled no)
			(sheetname "")
		)
		(fill
			(thermal_gap 0.5)
			(thermal_bridge_width 0.5)
			(island_removal_mode 0)
		)
		(polygon
			(pts
				(xy 365.15294 -40.9448) (xy 365.15294 -38.6334) (xy 363.95152 -38.6334) (xy 363.95152 -40.9448)
			)
		)
	)
	(zone
		(layer "F.Cu")
		(hatch none 0.5)
		(connect_pads
			(clearance 0)
		)
		(min_thickness 0.25)
		(keepout
			(tracks allowed)
			(vias allowed)
			(pads allowed)
			(copperpour allowed)
			(footprints allowed)
		)
		(placement
			(enabled no)
			(sheetname "")
		)
		(fill
			(thermal_gap 0.5)
			(thermal_bridge_width 0.5)
			(island_removal_mode 0)
		)
		(polygon
			(pts
				(xy 458.538326 -282.854908) (xy 458.538326 -282.626308) (xy 460.570326 -282.626308) (xy 460.570326 -282.854908)
			)
		)
	)
	(zone
		(layer "F.Cu")
		(hatch none 0.5)
		(connect_pads
			(clearance 0)
		)
		(min_thickness 0.25)
		(keepout
			(tracks allowed)
			(vias allowed)
			(pads allowed)
			(copperpour allowed)
			(footprints allowed)
		)
		(placement
			(enabled no)
			(sheetname "")
		)
		(fill
			(thermal_gap 0.5)
			(thermal_bridge_width 0.5)
			(island_removal_mode 0)
		)
		(polygon
			(pts
				(xy 382.57734 -289.034728) (xy 382.86436 -289.034728) (xy 382.89484 -289.004248) (xy 382.89484 -288.376868)
				(xy 382.80848 -288.290508) (xy 382.62052 -288.290508) (xy 382.54686 -288.364168) (xy 382.54686 -289.004248)
			)
		)
	)
	(zone
		(layer "F.Cu")
		(hatch none 0.5)
		(connect_pads
			(clearance 0)
		)
		(min_thickness 0.25)
		(keepout
			(tracks allowed)
			(vias allowed)
			(pads allowed)
			(copperpour allowed)
			(footprints not_allowed)
		)
		(placement
			(enabled no)
			(sheetname "")
		)
		(fill
			(thermal_gap 0.5)
			(thermal_bridge_width 0.5)
			(island_removal_mode 0)
		)
		(polygon
			(pts
				(arc
					(start 260.649974 -22.29993)
					(mid 265.649964 -17.29994)
					(end 270.649954 -22.29993)
				)
				(arc
					(start 270.649954 -22.29993)
					(mid 265.649964 -27.29992)
					(end 260.649974 -22.29993)
				)
			)
		)
	)
	(zone
		(layer "F.Cu")
		(hatch none 0.5)
		(connect_pads
			(clearance 0)
		)
		(min_thickness 0.25)
		(keepout
			(tracks allowed)
			(vias allowed)
			(pads allowed)
			(copperpour allowed)
			(footprints allowed)
		)
		(placement
			(enabled no)
			(sheetname "")
		)
		(fill
			(thermal_gap 0.5)
			(thermal_bridge_width 0.5)
			(island_removal_mode 0)
		)
		(polygon
			(pts
				(xy 161.891726 -246.304816) (xy 161.891726 -246.076216) (xy 163.923726 -246.076216) (xy 163.923726 -246.304816)
			)
		)
	)
	(zone
		(layer "F.Cu")
		(hatch none 0.5)
		(connect_pads
			(clearance 0)
		)
		(min_thickness 0.25)
		(keepout
			(tracks allowed)
			(vias allowed)
			(pads allowed)
			(copperpour allowed)
			(footprints allowed)
		)
		(placement
			(enabled no)
			(sheetname "")
		)
		(fill
			(thermal_gap 0.5)
			(thermal_bridge_width 0.5)
			(island_removal_mode 0)
		)
		(polygon
			(pts
				(xy 44.735242 -309.316628) (xy 44.735242 -308.87289) (xy 47.060358 -308.87289) (xy 47.060358 -309.316628)
			)
		)
	)
	(zone
		(layer "F.Cu")
		(hatch none 0.5)
		(connect_pads
			(clearance 0)
		)
		(min_thickness 0.25)
		(keepout
			(tracks allowed)
			(vias allowed)
			(pads allowed)
			(copperpour allowed)
			(footprints allowed)
		)
		(placement
			(enabled no)
			(sheetname "")
		)
		(fill
			(thermal_gap 0.5)
			(thermal_bridge_width 0.5)
			(island_removal_mode 0)
		)
		(polygon
			(pts
				(xy 128.6002 -361.714288) (xy 128.6002 -360.396028) (xy 129.77114 -360.396028) (xy 129.77114 -361.714288)
			)
		)
	)
	(zone
		(layer "F.Cu")
		(hatch none 0.5)
		(connect_pads
			(clearance 0)
		)
		(min_thickness 0.25)
		(keepout
			(tracks allowed)
			(vias allowed)
			(pads allowed)
			(copperpour allowed)
			(footprints allowed)
		)
		(placement
			(enabled no)
			(sheetname "")
		)
		(fill
			(thermal_gap 0.5)
			(thermal_bridge_width 0.5)
			(island_removal_mode 0)
		)
		(polygon
			(pts
				(xy 59.822842 -216.666572) (xy 59.822842 -216.222834) (xy 62.147958 -216.222834) (xy 62.147958 -216.666572)
			)
		)
	)
	(zone
		(layer "F.Cu")
		(hatch none 0.5)
		(connect_pads
			(clearance 0)
		)
		(min_thickness 0.25)
		(keepout
			(tracks allowed)
			(vias allowed)
			(pads allowed)
			(copperpour allowed)
			(footprints allowed)
		)
		(placement
			(enabled no)
			(sheetname "")
		)
		(fill
			(thermal_gap 0.5)
			(thermal_bridge_width 0.5)
			(island_removal_mode 0)
		)
		(polygon
			(pts
				(xy 424.919394 -200.407016) (xy 426.951394 -200.407016) (xy 426.951394 -200.178416) (xy 424.919394 -200.178416)
				(xy 424.788076 -200.178416) (xy 424.762168 -200.178416) (xy 424.762168 -200.407016) (xy 424.788076 -200.407016)
			)
		)
	)
	(zone
		(layer "F.Cu")
		(hatch none 0.5)
		(connect_pads
			(clearance 0)
		)
		(min_thickness 0.25)
		(keepout
			(tracks not_allowed)
			(vias allowed)
			(pads allowed)
			(copperpour not_allowed)
			(footprints allowed)
		)
		(placement
			(enabled no)
			(sheetname "")
		)
		(fill
			(thermal_gap 0.5)
			(thermal_bridge_width 0.5)
			(island_removal_mode 0)
		)
		(polygon
			(pts
				(arc
					(start 462.000092 -22.29993)
					(mid 464.800188 -19.499834)
					(end 467.60003 -22.29993)
				)
				(arc
					(start 467.60003 -22.29993)
					(mid 464.800188 -25.099772)
					(end 462.000092 -22.29993)
				)
			)
		)
	)
	(zone
		(layer "F.Cu")
		(hatch none 0.5)
		(connect_pads
			(clearance 0)
		)
		(min_thickness 0.25)
		(keepout
			(tracks allowed)
			(vias allowed)
			(pads allowed)
			(copperpour allowed)
			(footprints allowed)
		)
		(placement
			(enabled no)
			(sheetname "")
		)
		(fill
			(thermal_gap 0.5)
			(thermal_bridge_width 0.5)
			(island_removal_mode 0)
		)
		(polygon
			(pts
				(xy 409.831794 -225.67646) (xy 411.863794 -225.67646) (xy 411.863794 -225.90506) (xy 409.831794 -225.90506)
				(xy 409.69565 -225.90506) (xy 409.64866 -225.90506) (xy 409.64866 -225.67646) (xy 409.69565 -225.67646)
			)
		)
	)
	(zone
		(layer "F.Cu")
		(hatch none 0.5)
		(connect_pads
			(clearance 0)
		)
		(min_thickness 0.25)
		(keepout
			(tracks allowed)
			(vias allowed)
			(pads allowed)
			(copperpour allowed)
			(footprints allowed)
		)
		(placement
			(enabled no)
			(sheetname "")
		)
		(fill
			(thermal_gap 0.5)
			(thermal_bridge_width 0.5)
			(island_removal_mode 0)
		)
		(polygon
			(pts
				(xy 176.979326 -286.026352) (xy 179.011326 -286.026352) (xy 179.011326 -286.254952) (xy 176.979326 -286.254952)
				(xy 176.843182 -286.254952) (xy 176.796192 -286.254952) (xy 176.796192 -286.026352) (xy 176.843182 -286.026352)
			)
		)
	)
	(zone
		(layer "F.Cu")
		(hatch none 0.5)
		(connect_pads
			(clearance 0)
		)
		(min_thickness 0.25)
		(keepout
			(tracks allowed)
			(vias allowed)
			(pads allowed)
			(copperpour allowed)
			(footprints allowed)
		)
		(placement
			(enabled no)
			(sheetname "")
		)
		(fill
			(thermal_gap 0.5)
			(thermal_bridge_width 0.5)
			(island_removal_mode 0)
		)
		(polygon
			(pts
				(xy 161.891726 -261.605014) (xy 161.891726 -261.376414) (xy 163.923726 -261.376414) (xy 163.923726 -261.605014)
			)
		)
	)
	(zone
		(layer "F.Cu")
		(hatch none 0.5)
		(connect_pads
			(clearance 0)
		)
		(min_thickness 0.25)
		(keepout
			(tracks allowed)
			(vias allowed)
			(pads allowed)
			(copperpour allowed)
			(footprints allowed)
		)
		(placement
			(enabled no)
			(sheetname "")
		)
		(fill
			(thermal_gap 0.5)
			(thermal_bridge_width 0.5)
			(island_removal_mode 0)
		)
		(polygon
			(pts
				(xy 44.735242 -315.266578) (xy 44.735242 -314.82284) (xy 47.060358 -314.82284) (xy 47.060358 -315.266578)
			)
		)
	)
	(zone
		(layer "F.Cu")
		(hatch none 0.5)
		(connect_pads
			(clearance 0)
		)
		(min_thickness 0.25)
		(keepout
			(tracks not_allowed)
			(vias allowed)
			(pads allowed)
			(copperpour not_allowed)
			(footprints allowed)
		)
		(placement
			(enabled no)
			(sheetname "")
		)
		(fill
			(thermal_gap 0.5)
			(thermal_bridge_width 0.5)
			(island_removal_mode 0)
		)
		(polygon
			(pts
				(arc
					(start 378.899928 -22.29993)
					(mid 380.899924 -20.299934)
					(end 382.89992 -22.29993)
				)
				(arc
					(start 382.89992 -22.29993)
					(mid 380.899924 -24.299926)
					(end 378.899928 -22.29993)
				)
			)
		)
	)
	(zone
		(layer "F.Cu")
		(hatch none 0.5)
		(connect_pads
			(clearance 0)
		)
		(min_thickness 0.25)
		(keepout
			(tracks allowed)
			(vias allowed)
			(pads allowed)
			(copperpour allowed)
			(footprints allowed)
		)
		(placement
			(enabled no)
			(sheetname "")
		)
		(fill
			(thermal_gap 0.5)
			(thermal_bridge_width 0.5)
			(island_removal_mode 0)
		)
		(polygon
			(pts
				(xy 195.510658 -207.204818) (xy 195.510658 -206.976218) (xy 197.542658 -206.976218) (xy 197.542658 -207.204818)
			)
		)
	)
	(zone
		(layer "F.Cu")
		(hatch none 0.5)
		(connect_pads
			(clearance 0)
		)
		(min_thickness 0.25)
		(keepout
			(tracks allowed)
			(vias allowed)
			(pads allowed)
			(copperpour allowed)
			(footprints allowed)
		)
		(placement
			(enabled no)
			(sheetname "")
		)
		(fill
			(thermal_gap 0.5)
			(thermal_bridge_width 0.5)
			(island_removal_mode 0)
		)
		(polygon
			(pts
				(xy 338.4042 -289.016948) (xy 338.69122 -289.016948) (xy 338.7217 -288.986468) (xy 338.7217 -288.359088)
				(xy 338.63534 -288.272728) (xy 338.44738 -288.272728) (xy 338.37372 -288.346388) (xy 338.37372 -288.986468)
			)
		)
	)
	(zone
		(layer "F.Cu")
		(hatch none 0.5)
		(connect_pads
			(clearance 0)
		)
		(min_thickness 0.25)
		(keepout
			(tracks allowed)
			(vias allowed)
			(pads allowed)
			(copperpour allowed)
			(footprints allowed)
		)
		(placement
			(enabled no)
			(sheetname "")
		)
		(fill
			(thermal_gap 0.5)
			(thermal_bridge_width 0.5)
			(island_removal_mode 0)
		)
		(polygon
			(pts
				(xy 424.919394 -304.72634) (xy 426.951394 -304.72634) (xy 426.951394 -304.95494) (xy 424.919394 -304.95494)
				(xy 424.78325 -304.95494) (xy 424.73626 -304.95494) (xy 424.73626 -304.72634) (xy 424.78325 -304.72634)
			)
		)
	)
	(zone
		(layer "F.Cu")
		(hatch none 0.5)
		(connect_pads
			(clearance 0)
		)
		(min_thickness 0.25)
		(keepout
			(tracks allowed)
			(vias allowed)
			(pads allowed)
			(copperpour allowed)
			(footprints allowed)
		)
		(placement
			(enabled no)
			(sheetname "")
		)
		(fill
			(thermal_gap 0.5)
			(thermal_bridge_width 0.5)
			(island_removal_mode 0)
		)
		(polygon
			(pts
				(xy 440.006994 -294.526208) (xy 442.038994 -294.526208) (xy 442.038994 -294.754808) (xy 440.006994 -294.754808)
				(xy 439.875676 -294.754808) (xy 439.849768 -294.754808) (xy 439.849768 -294.526208) (xy 439.875676 -294.526208)
			)
		)
	)
	(zone
		(layer "F.Cu")
		(hatch none 0.5)
		(connect_pads
			(clearance 0)
		)
		(min_thickness 0.25)
		(keepout
			(tracks allowed)
			(vias allowed)
			(pads allowed)
			(copperpour allowed)
			(footprints allowed)
		)
		(placement
			(enabled no)
			(sheetname "")
		)
		(fill
			(thermal_gap 0.5)
			(thermal_bridge_width 0.5)
			(island_removal_mode 0)
		)
		(polygon
			(pts
				(xy 409.831794 -300.476412) (xy 411.863794 -300.476412) (xy 411.863794 -300.705012) (xy 409.831794 -300.705012)
				(xy 409.69565 -300.705012) (xy 409.64866 -300.705012) (xy 409.64866 -300.476412) (xy 409.69565 -300.476412)
			)
		)
	)
	(zone
		(layer "F.Cu")
		(hatch none 0.5)
		(connect_pads
			(clearance 0)
		)
		(min_thickness 0.25)
		(keepout
			(tracks allowed)
			(vias allowed)
			(pads allowed)
			(copperpour allowed)
			(footprints allowed)
		)
		(placement
			(enabled no)
			(sheetname "")
		)
		(fill
			(thermal_gap 0.5)
			(thermal_bridge_width 0.5)
			(island_removal_mode 0)
		)
		(polygon
			(pts
				(xy 167.378634 -276.90699) (xy 165.346634 -276.90699) (xy 165.346634 -276.904704) (xy 165.167818 -276.904704)
				(xy 164.977572 -276.904704) (xy 164.977572 -276.624288) (xy 164.848032 -276.624288) (xy 164.848032 -276.114764)
				(xy 165.05936 -276.114764) (xy 167.599614 -276.114764) (xy 167.9067 -276.114764) (xy 167.9067 -276.660356)
				(xy 167.9067 -276.90699) (xy 167.659304 -276.90699) (xy 167.561768 -276.90699) (xy 167.514778 -276.90699)
			)
		)
	)
	(zone
		(layer "F.Cu")
		(hatch none 0.5)
		(connect_pads
			(clearance 0)
		)
		(min_thickness 0.25)
		(keepout
			(tracks allowed)
			(vias allowed)
			(pads allowed)
			(copperpour allowed)
			(footprints allowed)
		)
		(placement
			(enabled no)
			(sheetname "")
		)
		(fill
			(thermal_gap 0.5)
			(thermal_bridge_width 0.5)
			(island_removal_mode 0)
		)
		(polygon
			(pts
				(xy 424.919394 -211.2264) (xy 426.951394 -211.2264) (xy 426.951394 -211.455) (xy 424.919394 -211.455)
				(xy 424.78325 -211.455) (xy 424.73626 -211.455) (xy 424.73626 -211.2264) (xy 424.78325 -211.2264)
			)
		)
	)
	(zone
		(layer "F.Cu")
		(hatch none 0.5)
		(connect_pads
			(clearance 0)
		)
		(min_thickness 0.25)
		(keepout
			(tracks allowed)
			(vias allowed)
			(pads allowed)
			(copperpour allowed)
			(footprints allowed)
		)
		(placement
			(enabled no)
			(sheetname "")
		)
		(fill
			(thermal_gap 0.5)
			(thermal_bridge_width 0.5)
			(island_removal_mode 0)
		)
		(polygon
			(pts
				(xy 335.72958 -62.901068) (xy 335.72958 -59.299348) (xy 337.52282 -59.299348) (xy 337.52282 -62.901068)
			)
		)
	)
	(zone
		(layer "F.Cu")
		(hatch none 0.5)
		(connect_pads
			(clearance 0)
		)
		(min_thickness 0.25)
		(keepout
			(tracks not_allowed)
			(vias allowed)
			(pads allowed)
			(copperpour not_allowed)
			(footprints allowed)
		)
		(placement
			(enabled no)
			(sheetname "")
		)
		(fill
			(thermal_gap 0.5)
			(thermal_bridge_width 0.5)
			(island_removal_mode 0)
		)
		(polygon
			(pts
				(arc
					(start 62.782958 -50.249836)
					(mid 59.583066 -47.049944)
					(end 62.782958 -43.850052)
				)
				(arc
					(start 64.382904 -43.850052)
					(mid 67.582796 -47.049944)
					(end 64.382904 -50.249836)
				)
			)
		)
		(polygon
			(pts
				(arc
					(start 64.382904 -45.449998)
					(mid 65.98285 -47.049944)
					(end 64.382904 -48.64989)
				)
				(arc
					(start 62.782958 -48.64989)
					(mid 61.183012 -47.049944)
					(end 62.782958 -45.449998)
				)
			)
		)
	)
	(zone
		(layer "F.Cu")
		(hatch none 0.5)
		(connect_pads
			(clearance 0)
		)
		(min_thickness 0.25)
		(keepout
			(tracks allowed)
			(vias allowed)
			(pads allowed)
			(copperpour allowed)
			(footprints allowed)
		)
		(placement
			(enabled no)
			(sheetname "")
		)
		(fill
			(thermal_gap 0.5)
			(thermal_bridge_width 0.5)
			(island_removal_mode 0)
		)
		(polygon
			(pts
				(xy 194.277742 -269.028672) (xy 194.277742 -269.265908) (xy 194.415664 -269.265908) (xy 194.458844 -269.309088)
				(xy 194.458844 -269.44193) (xy 194.458844 -269.745968) (xy 194.3862 -269.818612) (xy 191.845946 -269.818612)
				(xy 191.704722 -269.677388) (xy 191.704722 -269.480284) (xy 191.786256 -269.39875) (xy 191.786256 -269.026386)
				(xy 191.786256 -268.435328) (xy 194.277742 -268.435328)
			)
		)
	)
	(zone
		(layer "F.Cu")
		(hatch none 0.5)
		(connect_pads
			(clearance 0)
		)
		(min_thickness 0.25)
		(keepout
			(tracks allowed)
			(vias allowed)
			(pads allowed)
			(copperpour allowed)
			(footprints allowed)
		)
		(placement
			(enabled no)
			(sheetname "")
		)
		(fill
			(thermal_gap 0.5)
			(thermal_bridge_width 0.5)
			(island_removal_mode 0)
		)
		(polygon
			(pts
				(xy 334.05064 -218.486228) (xy 334.33766 -218.486228) (xy 334.36814 -218.455748) (xy 334.36814 -217.828368)
				(xy 334.28178 -217.742008) (xy 334.09382 -217.742008) (xy 334.02016 -217.815668) (xy 334.02016 -218.455748)
			)
		)
	)
	(zone
		(layer "F.Cu")
		(hatch none 0.5)
		(connect_pads
			(clearance 0)
		)
		(min_thickness 0.25)
		(keepout
			(tracks allowed)
			(vias allowed)
			(pads allowed)
			(copperpour allowed)
			(footprints allowed)
		)
		(placement
			(enabled no)
			(sheetname "")
		)
		(fill
			(thermal_gap 0.5)
			(thermal_bridge_width 0.5)
			(island_removal_mode 0)
		)
		(polygon
			(pts
				(xy 304.319178 -312.716418) (xy 304.319178 -312.27268) (xy 306.644294 -312.27268) (xy 306.644294 -312.716418)
			)
		)
	)
	(zone
		(layer "F.Cu")
		(hatch none 0.5)
		(connect_pads
			(clearance 0)
		)
		(min_thickness 0.25)
		(keepout
			(tracks allowed)
			(vias allowed)
			(pads allowed)
			(copperpour allowed)
			(footprints allowed)
		)
		(placement
			(enabled no)
			(sheetname "")
		)
		(fill
			(thermal_gap 0.5)
			(thermal_bridge_width 0.5)
			(island_removal_mode 0)
		)
		(polygon
			(pts
				(xy 44.735242 -274.466558) (xy 44.735242 -274.02282) (xy 47.060358 -274.02282) (xy 47.060358 -274.466558)
			)
		)
	)
	(zone
		(layer "F.Cu")
		(hatch none 0.5)
		(connect_pads
			(clearance 0)
		)
		(min_thickness 0.25)
		(keepout
			(tracks allowed)
			(vias allowed)
			(pads allowed)
			(copperpour allowed)
			(footprints allowed)
		)
		(placement
			(enabled no)
			(sheetname "")
		)
		(fill
			(thermal_gap 0.5)
			(thermal_bridge_width 0.5)
			(island_removal_mode 0)
		)
		(polygon
			(pts
				(xy 59.822842 -295.716452) (xy 59.822842 -295.272714) (xy 62.147958 -295.272714) (xy 62.147958 -295.716452)
			)
		)
	)
	(zone
		(layer "F.Cu")
		(hatch none 0.5)
		(connect_pads
			(clearance 0)
		)
		(min_thickness 0.25)
		(keepout
			(tracks allowed)
			(vias allowed)
			(pads allowed)
			(copperpour allowed)
			(footprints allowed)
		)
		(placement
			(enabled no)
			(sheetname "")
		)
		(fill
			(thermal_gap 0.5)
			(thermal_bridge_width 0.5)
			(island_removal_mode 0)
		)
		(polygon
			(pts
				(xy 157.791658 -218.254834) (xy 157.791658 -218.026234) (xy 159.823658 -218.026234) (xy 159.823658 -218.254834)
			)
		)
	)
	(zone
		(layer "F.Cu")
		(hatch none 0.5)
		(connect_pads
			(clearance 0)
		)
		(min_thickness 0.25)
		(keepout
			(tracks allowed)
			(vias allowed)
			(pads allowed)
			(copperpour allowed)
			(footprints allowed)
		)
		(placement
			(enabled no)
			(sheetname "")
		)
		(fill
			(thermal_gap 0.5)
			(thermal_bridge_width 0.5)
			(island_removal_mode 0)
		)
		(polygon
			(pts
				(xy 192.066926 -266.476226) (xy 194.098926 -266.476226) (xy 194.098926 -266.704826) (xy 192.066926 -266.704826)
				(xy 191.900302 -266.704826) (xy 191.900302 -266.476226)
			)
		)
	)
	(zone
		(layer "F.Cu")
		(hatch none 0.5)
		(connect_pads
			(clearance 0)
		)
		(min_thickness 0.25)
		(keepout
			(tracks allowed)
			(vias allowed)
			(pads allowed)
			(copperpour allowed)
			(footprints allowed)
		)
		(placement
			(enabled no)
			(sheetname "")
		)
		(fill
			(thermal_gap 0.5)
			(thermal_bridge_width 0.5)
			(island_removal_mode 0)
		)
		(polygon
			(pts
				(xy 165.335458 -222.505016) (xy 165.335458 -222.276416) (xy 167.367458 -222.276416) (xy 167.367458 -222.505016)
			)
		)
	)
	(zone
		(layer "F.Cu")
		(hatch none 0.5)
		(connect_pads
			(clearance 0)
		)
		(min_thickness 0.25)
		(keepout
			(tracks allowed)
			(vias allowed)
			(pads allowed)
			(copperpour allowed)
			(footprints allowed)
		)
		(placement
			(enabled no)
			(sheetname "")
		)
		(fill
			(thermal_gap 0.5)
			(thermal_bridge_width 0.5)
			(island_removal_mode 0)
		)
		(polygon
			(pts
				(xy 84.32292 -103.472488) (xy 84.32292 -102.039928) (xy 85.60562 -102.039928) (xy 85.60562 -103.472488)
			)
		)
	)
	(zone
		(layer "F.Cu")
		(hatch none 0.5)
		(connect_pads
			(clearance 0)
		)
		(min_thickness 0.25)
		(keepout
			(tracks allowed)
			(vias allowed)
			(pads allowed)
			(copperpour allowed)
			(footprints allowed)
		)
		(placement
			(enabled no)
			(sheetname "")
		)
		(fill
			(thermal_gap 0.5)
			(thermal_bridge_width 0.5)
			(island_removal_mode 0)
		)
		(polygon
			(pts
				(xy 11.11631 -229.41661) (xy 11.11631 -228.972872) (xy 13.441426 -228.972872) (xy 13.441426 -229.41661)
			)
		)
	)
	(zone
		(layer "F.Cu")
		(hatch none 0.5)
		(connect_pads
			(clearance 0)
		)
		(min_thickness 0.25)
		(keepout
			(tracks allowed)
			(vias allowed)
			(pads allowed)
			(copperpour allowed)
			(footprints allowed)
		)
		(placement
			(enabled no)
			(sheetname "")
		)
		(fill
			(thermal_gap 0.5)
			(thermal_bridge_width 0.5)
			(island_removal_mode 0)
		)
		(polygon
			(pts
				(xy 310.995822 -410.948886) (xy 310.995822 -406.105868) (xy 312.880248 -406.105868) (xy 312.880248 -410.948886)
			)
		)
	)
	(zone
		(layer "F.Cu")
		(hatch none 0.5)
		(connect_pads
			(clearance 0)
		)
		(min_thickness 0.25)
		(keepout
			(tracks allowed)
			(vias allowed)
			(pads allowed)
			(copperpour allowed)
			(footprints allowed)
		)
		(placement
			(enabled no)
			(sheetname "")
		)
		(fill
			(thermal_gap 0.5)
			(thermal_bridge_width 0.5)
			(island_removal_mode 0)
		)
		(polygon
			(pts
				(xy 289.231578 -277.016464) (xy 289.231578 -276.572726) (xy 291.556694 -276.572726) (xy 291.556694 -277.016464)
			)
		)
	)
	(zone
		(layer "F.Cu")
		(hatch none 0.5)
		(connect_pads
			(clearance 0)
		)
		(min_thickness 0.25)
		(keepout
			(tracks allowed)
			(vias allowed)
			(pads allowed)
			(copperpour allowed)
			(footprints allowed)
		)
		(placement
			(enabled no)
			(sheetname "")
		)
		(fill
			(thermal_gap 0.5)
			(thermal_bridge_width 0.5)
			(island_removal_mode 0)
		)
		(polygon
			(pts
				(xy 165.335458 -224.204784) (xy 165.335458 -223.976184) (xy 167.367458 -223.976184) (xy 167.367458 -224.204784)
			)
		)
	)
	(zone
		(layer "F.Cu")
		(hatch none 0.5)
		(connect_pads
			(clearance 0)
		)
		(min_thickness 0.25)
		(keepout
			(tracks allowed)
			(vias allowed)
			(pads allowed)
			(copperpour allowed)
			(footprints allowed)
		)
		(placement
			(enabled no)
			(sheetname "")
		)
		(fill
			(thermal_gap 0.5)
			(thermal_bridge_width 0.5)
			(island_removal_mode 0)
		)
		(polygon
			(pts
				(xy 289.231578 -308.46649) (xy 289.231578 -308.022752) (xy 291.556694 -308.022752) (xy 291.556694 -308.46649)
			)
		)
	)
	(zone
		(layer "F.Cu")
		(hatch none 0.5)
		(connect_pads
			(clearance 0)
		)
		(min_thickness 0.25)
		(keepout
			(tracks allowed)
			(vias allowed)
			(pads allowed)
			(copperpour allowed)
			(footprints allowed)
		)
		(placement
			(enabled no)
			(sheetname "")
		)
		(fill
			(thermal_gap 0.5)
			(thermal_bridge_width 0.5)
			(island_removal_mode 0)
		)
		(polygon
			(pts
				(xy 168.34358 -358.935528) (xy 168.34358 -356.078028) (xy 173.31436 -356.078028) (xy 173.7233 -356.486968)
				(xy 174.45228 -356.486968) (xy 174.88408 -356.918768) (xy 174.88408 -357.690928) (xy 174.88408 -358.513888)
				(xy 174.46244 -358.935528) (xy 173.31436 -358.935528)
			)
		)
	)
	(zone
		(layer "F.Cu")
		(hatch none 0.5)
		(connect_pads
			(clearance 0)
		)
		(min_thickness 0.25)
		(keepout
			(tracks allowed)
			(vias allowed)
			(pads allowed)
			(copperpour allowed)
			(footprints allowed)
		)
		(placement
			(enabled no)
			(sheetname "")
		)
		(fill
			(thermal_gap 0.5)
			(thermal_bridge_width 0.5)
			(island_removal_mode 0)
		)
		(polygon
			(pts
				(xy 176.979326 -210.376262) (xy 179.011326 -210.376262) (xy 179.011326 -210.604862) (xy 176.979326 -210.604862)
				(xy 176.848008 -210.604862) (xy 176.8221 -210.604862) (xy 176.8221 -210.376262) (xy 176.848008 -210.376262)
			)
		)
	)
	(zone
		(layer "F.Cu")
		(hatch none 0.5)
		(connect_pads
			(clearance 0)
		)
		(min_thickness 0.25)
		(keepout
			(tracks allowed)
			(vias allowed)
			(pads allowed)
			(copperpour allowed)
			(footprints allowed)
		)
		(placement
			(enabled no)
			(sheetname "")
		)
		(fill
			(thermal_gap 0.5)
			(thermal_bridge_width 0.5)
			(island_removal_mode 0)
		)
		(polygon
			(pts
				(xy 41.29151 -241.31651) (xy 41.29151 -240.872772) (xy 43.616626 -240.872772) (xy 43.616626 -241.31651)
			)
		)
	)
	(zone
		(layer "F.Cu")
		(hatch none 0.5)
		(connect_pads
			(clearance 0)
		)
		(min_thickness 0.25)
		(keepout
			(tracks allowed)
			(vias allowed)
			(pads allowed)
			(copperpour allowed)
			(footprints allowed)
		)
		(placement
			(enabled no)
			(sheetname "")
		)
		(fill
			(thermal_gap 0.5)
			(thermal_bridge_width 0.5)
			(island_removal_mode 0)
		)
		(polygon
			(pts
				(xy 207.154526 -260.754876) (xy 207.154526 -260.526276) (xy 209.186526 -260.526276) (xy 209.186526 -260.754876)
			)
		)
	)
	(zone
		(layer "F.Cu")
		(hatch none 0.5)
		(connect_pads
			(clearance 0)
		)
		(min_thickness 0.25)
		(keepout
			(tracks allowed)
			(vias allowed)
			(pads allowed)
			(copperpour allowed)
			(footprints allowed)
		)
		(placement
			(enabled no)
			(sheetname "")
		)
		(fill
			(thermal_gap 0.5)
			(thermal_bridge_width 0.5)
			(island_removal_mode 0)
		)
		(polygon
			(pts
				(xy 11.11631 -313.566556) (xy 11.11631 -313.122818) (xy 13.441426 -313.122818) (xy 13.441426 -313.566556)
			)
		)
	)
	(zone
		(layer "F.Cu")
		(hatch none 0.5)
		(connect_pads
			(clearance 0)
		)
		(min_thickness 0.25)
		(keepout
			(tracks allowed)
			(vias allowed)
			(pads allowed)
			(copperpour allowed)
			(footprints allowed)
		)
		(placement
			(enabled no)
			(sheetname "")
		)
		(fill
			(thermal_gap 0.5)
			(thermal_bridge_width 0.5)
			(island_removal_mode 0)
		)
		(polygon
			(pts
				(xy 262.50011 -209.0166) (xy 262.50011 -208.572862) (xy 264.825226 -208.572862) (xy 264.825226 -209.0166)
			)
		)
	)
	(zone
		(layer "F.Cu")
		(hatch none 0.5)
		(connect_pads
			(clearance 0)
		)
		(min_thickness 0.25)
		(keepout
			(tracks allowed)
			(vias allowed)
			(pads allowed)
			(copperpour allowed)
			(footprints allowed)
		)
		(placement
			(enabled no)
			(sheetname "")
		)
		(fill
			(thermal_gap 0.5)
			(thermal_bridge_width 0.5)
			(island_removal_mode 0)
		)
		(polygon
			(pts
				(xy 157.848554 -309.204868) (xy 157.848554 -308.976268) (xy 159.778954 -308.976268) (xy 159.778954 -309.204868)
			)
		)
	)
	(zone
		(layer "F.Cu")
		(hatch none 0.5)
		(connect_pads
			(clearance 0)
		)
		(min_thickness 0.25)
		(keepout
			(tracks allowed)
			(vias allowed)
			(pads allowed)
			(copperpour allowed)
			(footprints allowed)
		)
		(placement
			(enabled no)
			(sheetname "")
		)
		(fill
			(thermal_gap 0.5)
			(thermal_bridge_width 0.5)
			(island_removal_mode 0)
		)
		(polygon
			(pts
				(xy 405.731726 -311.755028) (xy 405.731726 -311.526428) (xy 407.763726 -311.526428) (xy 407.763726 -311.755028)
			)
		)
	)
	(zone
		(layer "F.Cu")
		(hatch none 0.5)
		(connect_pads
			(clearance 0)
		)
		(min_thickness 0.25)
		(keepout
			(tracks allowed)
			(vias allowed)
			(pads allowed)
			(copperpour allowed)
			(footprints allowed)
		)
		(placement
			(enabled no)
			(sheetname "")
		)
		(fill
			(thermal_gap 0.5)
			(thermal_bridge_width 0.5)
			(island_removal_mode 0)
		)
		(polygon
			(pts
				(xy 358.44734 -215.224868) (xy 358.73436 -215.224868) (xy 358.76484 -215.194388) (xy 358.76484 -214.567008)
				(xy 358.67848 -214.480648) (xy 358.49052 -214.480648) (xy 358.41686 -214.554308) (xy 358.41686 -215.194388)
			)
		)
	)
	(zone
		(layer "F.Cu")
		(hatch none 0.5)
		(connect_pads
			(clearance 0)
		)
		(min_thickness 0.25)
		(keepout
			(tracks allowed)
			(vias allowed)
			(pads allowed)
			(copperpour allowed)
			(footprints allowed)
		)
		(placement
			(enabled no)
			(sheetname "")
		)
		(fill
			(thermal_gap 0.5)
			(thermal_bridge_width 0.5)
			(island_removal_mode 0)
		)
		(polygon
			(pts
				(xy 310.088026 -277.016464) (xy 307.76291 -277.016464) (xy 307.44922 -277.016464) (xy 307.44922 -276.002496)
				(xy 310.348376 -276.002496) (xy 310.348376 -277.016464)
			)
		)
	)
	(zone
		(layer "F.Cu")
		(hatch none 0.5)
		(connect_pads
			(clearance 0)
		)
		(min_thickness 0.25)
		(keepout
			(tracks allowed)
			(vias allowed)
			(pads allowed)
			(copperpour allowed)
			(footprints not_allowed)
		)
		(placement
			(enabled no)
			(sheetname "")
		)
		(fill
			(thermal_gap 0.5)
			(thermal_bridge_width 0.5)
			(island_removal_mode 0)
		)
		(polygon
			(pts
				(xy 316.869826 -314.770008) (xy 402.869908 -314.770008) (xy 402.869908 -188.770006) (xy 316.869826 -188.770006)
			)
		)
	)
	(zone
		(layer "F.Cu")
		(hatch none 0.5)
		(connect_pads
			(clearance 0)
		)
		(min_thickness 0.25)
		(keepout
			(tracks allowed)
			(vias allowed)
			(pads allowed)
			(copperpour allowed)
			(footprints allowed)
		)
		(placement
			(enabled no)
			(sheetname "")
		)
		(fill
			(thermal_gap 0.5)
			(thermal_bridge_width 0.5)
			(island_removal_mode 0)
		)
		(polygon
			(pts
				(xy 443.450726 -286.254952) (xy 443.450726 -286.026352) (xy 445.482726 -286.026352) (xy 445.482726 -286.254952)
			)
		)
	)
	(zone
		(layer "F.Cu")
		(hatch none 0.5)
		(connect_pads
			(clearance 0)
		)
		(min_thickness 0.25)
		(keepout
			(tracks allowed)
			(vias allowed)
			(pads allowed)
			(copperpour allowed)
			(footprints allowed)
		)
		(placement
			(enabled no)
			(sheetname "")
		)
		(fill
			(thermal_gap 0.5)
			(thermal_bridge_width 0.5)
			(island_removal_mode 0)
		)
		(polygon
			(pts
				(xy 207.154526 -240.976404) (xy 209.186526 -240.976404) (xy 209.186526 -241.205004) (xy 207.154526 -241.205004)
				(xy 207.018382 -241.205004) (xy 206.971392 -241.205004) (xy 206.971392 -240.976404) (xy 207.018382 -240.976404)
			)
		)
	)
	(zone
		(layer "F.Cu")
		(hatch none 0.5)
		(connect_pads
			(clearance 0)
		)
		(min_thickness 0.25)
		(keepout
			(tracks allowed)
			(vias allowed)
			(pads allowed)
			(copperpour allowed)
			(footprints allowed)
		)
		(placement
			(enabled no)
			(sheetname "")
		)
		(fill
			(thermal_gap 0.5)
			(thermal_bridge_width 0.5)
			(island_removal_mode 0)
		)
		(polygon
			(pts
				(xy 176.979326 -228.456998) (xy 179.011326 -228.456998) (xy 179.011326 -228.228398) (xy 176.979326 -228.228398)
				(xy 176.848008 -228.228398) (xy 176.8221 -228.228398) (xy 176.8221 -228.456998) (xy 176.848008 -228.456998)
			)
		)
	)
	(zone
		(layer "F.Cu")
		(hatch none 0.5)
		(connect_pads
			(clearance 0)
		)
		(min_thickness 0.25)
		(keepout
			(tracks allowed)
			(vias allowed)
			(pads allowed)
			(copperpour allowed)
			(footprints allowed)
		)
		(placement
			(enabled no)
			(sheetname "")
		)
		(fill
			(thermal_gap 0.5)
			(thermal_bridge_width 0.5)
			(island_removal_mode 0)
		)
		(polygon
			(pts
				(xy 14.560042 -292.316662) (xy 14.560042 -291.872924) (xy 16.885158 -291.872924) (xy 16.885158 -292.316662)
			)
		)
	)
	(zone
		(layer "F.Cu")
		(hatch none 0.5)
		(connect_pads
			(clearance 0)
		)
		(min_thickness 0.25)
		(keepout
			(tracks allowed)
			(vias allowed)
			(pads allowed)
			(copperpour allowed)
			(footprints not_allowed)
		)
		(placement
			(enabled no)
			(sheetname "")
		)
		(fill
			(thermal_gap 0.5)
			(thermal_bridge_width 0.5)
			(island_removal_mode 0)
		)
		(polygon
			(pts
				(arc
					(start 263.645396 -51.999896)
					(mid 268.645386 -46.999906)
					(end 273.645376 -51.999896)
				)
				(arc
					(start 273.645376 -51.999896)
					(mid 268.645386 -56.999886)
					(end 263.645396 -51.999896)
				)
			)
		)
	)
	(zone
		(layer "F.Cu")
		(hatch none 0.5)
		(connect_pads
			(clearance 0)
		)
		(min_thickness 0.25)
		(keepout
			(tracks allowed)
			(vias allowed)
			(pads allowed)
			(copperpour allowed)
			(footprints not_allowed)
		)
		(placement
			(enabled no)
			(sheetname "")
		)
		(fill
			(thermal_gap 0.5)
			(thermal_bridge_width 0.5)
			(island_removal_mode 0)
		)
		(polygon
			(pts
				(arc
					(start 314.900056 -160.50006)
					(mid 322.90004 -152.500076)
					(end 330.900024 -160.50006)
				)
				(arc
					(start 330.900024 -160.50006)
					(mid 322.90004 -168.500044)
					(end 314.900056 -160.50006)
				)
			)
		)
	)
	(zone
		(layer "F.Cu")
		(hatch none 0.5)
		(connect_pads
			(clearance 0)
		)
		(min_thickness 0.25)
		(keepout
			(tracks allowed)
			(vias allowed)
			(pads allowed)
			(copperpour allowed)
			(footprints allowed)
		)
		(placement
			(enabled no)
			(sheetname "")
		)
		(fill
			(thermal_gap 0.5)
			(thermal_bridge_width 0.5)
			(island_removal_mode 0)
		)
		(polygon
			(pts
				(xy 123.189746 -360.717592) (xy 124.571506 -360.717592) (xy 124.939806 -360.349292) (xy 124.939806 -356.999032)
				(xy 122.267726 -354.326952) (xy 118.064026 -354.326952) (xy 118.013226 -354.377752) (xy 118.013226 -355.551232)
				(xy 118.102126 -355.640132) (xy 121.620026 -355.640132) (xy 122.260106 -356.280212) (xy 122.260106 -359.787952)
			)
		)
	)
	(zone
		(layer "F.Cu")
		(hatch none 0.5)
		(connect_pads
			(clearance 0)
		)
		(min_thickness 0.25)
		(keepout
			(tracks allowed)
			(vias allowed)
			(pads allowed)
			(copperpour allowed)
			(footprints allowed)
		)
		(placement
			(enabled no)
			(sheetname "")
		)
		(fill
			(thermal_gap 0.5)
			(thermal_bridge_width 0.5)
			(island_removal_mode 0)
		)
		(polygon
			(pts
				(xy 304.319178 -261.71652) (xy 304.319178 -261.272782) (xy 306.644294 -261.272782) (xy 306.644294 -261.71652)
			)
		)
	)
	(zone
		(layer "F.Cu")
		(hatch none 0.5)
		(connect_pads
			(clearance 0)
		)
		(min_thickness 0.25)
		(keepout
			(tracks allowed)
			(vias allowed)
			(pads allowed)
			(copperpour allowed)
			(footprints allowed)
		)
		(placement
			(enabled no)
			(sheetname "")
		)
		(fill
			(thermal_gap 0.5)
			(thermal_bridge_width 0.5)
			(island_removal_mode 0)
		)
		(polygon
			(pts
				(xy 292.67531 -198.816468) (xy 292.67531 -198.37273) (xy 295.000426 -198.37273) (xy 295.000426 -198.816468)
			)
		)
	)
	(zone
		(layer "F.Cu")
		(hatch none 0.5)
		(connect_pads
			(clearance 0)
		)
		(min_thickness 0.25)
		(keepout
			(tracks allowed)
			(vias allowed)
			(pads allowed)
			(copperpour allowed)
			(footprints allowed)
		)
		(placement
			(enabled no)
			(sheetname "")
		)
		(fill
			(thermal_gap 0.5)
			(thermal_bridge_width 0.5)
			(island_removal_mode 0)
		)
		(polygon
			(pts
				(xy 139.762992 -271.975834) (xy 141.439392 -273.652234) (xy 141.460728 -273.67357) (xy 141.460728 -273.790918)
				(xy 141.302232 -273.949414) (xy 141.206982 -273.949414) (xy 140.362178 -273.10461) (xy 140.342366 -273.10461)
				(xy 140.18768 -273.259296) (xy 140.18768 -273.30908) (xy 141.00683 -274.12823) (xy 141.00683 -274.258786)
				(xy 140.606018 -274.659598) (xy 140.606018 -274.812252) (xy 140.120116 -275.298154) (xy 140.120116 -275.313648)
				(xy 140.312394 -275.505926) (xy 140.312394 -275.585428) (xy 139.90193 -275.995892) (xy 139.90193 -276.023578)
				(xy 139.90193 -276.206204) (xy 140.130022 -276.434296) (xy 140.130022 -276.51202) (xy 139.630404 -277.011638)
				(xy 139.630404 -277.161498) (xy 139.19073 -277.601172) (xy 139.344146 -277.754588) (xy 139.634722 -278.045418)
				(xy 139.634722 -278.654002) (xy 139.737338 -278.756618) (xy 139.737338 -279.357074) (xy 139.95273 -279.572212)
				(xy 139.95273 -280.115772) (xy 140.130276 -280.293318) (xy 140.130276 -281.069288) (xy 140.021056 -281.178508)
				(xy 138.876024 -281.178508) (xy 138.876024 -286.272224) (xy 138.863324 -286.284924) (xy 138.863578 -291.326824)
				(xy 138.80592 -291.384482) (xy 138.80592 -296.768012) (xy 138.678158 -296.895774) (xy 138.678158 -296.999152)
				(xy 139.087098 -297.408092) (xy 139.17422 -297.408092) (xy 140.848842 -297.408092) (xy 140.994638 -297.408092)
				(xy 142.892018 -295.510712) (xy 142.892018 -295.479724) (xy 142.844266 -295.431972) (xy 142.771114 -295.35882)
				(xy 142.610586 -295.198292) (xy 142.610586 -295.162732) (xy 143.557498 -294.21582) (xy 143.557498 -294.118284)
				(xy 143.466566 -294.027352) (xy 143.255492 -293.816278) (xy 143.687038 -293.384732) (xy 143.687038 -292.886892)
				(xy 143.605758 -292.805612) (xy 144.733518 -291.677852) (xy 144.758918 -291.677852) (xy 145.297398 -291.139372)
				(xy 145.297398 -291.104828) (xy 145.221452 -291.028882) (xy 144.840452 -290.647882) (xy 144.469866 -290.277296)
				(xy 144.3482 -290.15563) (xy 145.094198 -289.409632) (xy 145.094198 -289.054032) (xy 145.656046 -288.492184)
				(xy 145.656046 -288.401252) (xy 145.656046 -288.220912) (xy 145.886678 -287.99028) (xy 145.886678 -287.674812)
				(xy 146.240246 -287.321244) (xy 146.240246 -286.936434) (xy 146.240246 -285.971234) (xy 146.392646 -285.818834)
				(xy 146.545046 -285.818834) (xy 146.647916 -285.818834) (xy 149.381718 -283.085032) (xy 149.381718 -282.98013)
				(xy 149.344634 -282.943046) (xy 148.857462 -282.455874) (xy 148.857462 -282.407868) (xy 149.474428 -281.790902)
				(xy 150.202646 -281.062684) (xy 150.687278 -280.578052) (xy 150.687278 -280.184352) (xy 150.507446 -280.00452)
				(xy 150.507446 -279.973532) (xy 150.656798 -279.82418) (xy 150.656798 -279.214834) (xy 150.910798 -278.960834)
				(xy 151.066246 -278.960834) (xy 151.199596 -278.960834) (xy 151.529034 -278.631396) (xy 151.529034 -278.498046)
				(xy 151.354536 -278.323294) (xy 151.354536 -277.454868) (xy 152.336246 -277.454868) (xy 152.460198 -277.454868)
				(xy 152.460198 -274.3962) (xy 152.668986 -274.187412) (xy 153.301192 -274.187412) (xy 153.417778 -274.187412)
				(xy 153.417778 -273.427952) (xy 153.212546 -273.427952) (xy 152.531572 -273.427952) (xy 152.056592 -272.952972)
				(xy 152.056592 -272.856452) (xy 152.442418 -272.470626) (xy 152.442418 -272.03146) (xy 152.285192 -271.874234)
				(xy 152.069292 -271.658334) (xy 152.310592 -271.417034) (xy 152.310592 -271.251172) (xy 152.477978 -271.083786)
				(xy 152.477978 -271.075912) (xy 152.3111 -270.909034) (xy 152.310592 -270.909034) (xy 151.155654 -269.754096)
				(xy 151.155654 -268.023848) (xy 151.027638 -267.895832) (xy 150.847298 -267.895832) (xy 150.440136 -267.895832)
				(xy 142.222728 -259.678424) (xy 142.126208 -259.678424) (xy 141.234668 -260.56971) (xy 141.234668 -260.595618)
				(xy 142.436342 -261.797292) (xy 142.436342 -261.880858) (xy 142.026132 -262.291068) (xy 141.9606 -262.291068)
				(xy 141.722602 -262.05307) (xy 141.722602 -262.052308) (xy 141.72184 -262.052308) (xy 141.323314 -261.653782)
				(xy 141.284198 -261.653782) (xy 140.988542 -261.949438) (xy 140.988542 -262.025638) (xy 141.087602 -262.124698)
				(xy 141.087602 -262.259826) (xy 141.050264 -262.297164) (xy 140.253212 -263.094216) (xy 140.253212 -263.254744)
				(xy 141.371574 -264.373106) (xy 141.371574 -264.537952) (xy 140.776706 -265.13282) (xy 140.617956 -265.13282)
				(xy 140.14196 -264.656824) (xy 140.078714 -264.656824) (xy 139.94765 -264.787888) (xy 139.94765 -264.859262)
				(xy 141.143482 -266.055094) (xy 141.143482 -266.261088) (xy 140.419836 -266.984734) (xy 140.419836 -267.028676)
				(xy 140.658596 -267.267436) (xy 140.658596 -267.32103) (xy 140.450062 -267.529564) (xy 140.318744 -267.529564)
				(xy 140.114528 -267.325348) (xy 140.093192 -267.325348) (xy 139.370816 -268.047724) (xy 139.370816 -268.095476)
				(xy 141.167358 -269.892018) (xy 141.167358 -270.023082) (xy 140.830046 -270.360394) (xy 140.830046 -270.425672)
				(xy 140.923264 -270.51889) (xy 140.923264 -270.774668) (xy 140.201904 -271.496028) (xy 140.164566 -271.496028)
				(xy 140.109448 -271.44091) (xy 140.095986 -271.427448) (xy 139.958064 -271.427448) (xy 139.638532 -271.74698)
				(xy 139.638532 -271.85112) (xy 139.685268 -271.897856) (xy 139.742672 -271.95526)
			)
		)
	)
	(zone
		(layer "F.Cu")
		(hatch none 0.5)
		(connect_pads
			(clearance 0)
		)
		(min_thickness 0.25)
		(keepout
			(tracks not_allowed)
			(vias allowed)
			(pads allowed)
			(copperpour not_allowed)
			(footprints allowed)
		)
		(placement
			(enabled no)
			(sheetname "")
		)
		(fill
			(thermal_gap 0.5)
			(thermal_bridge_width 0.5)
			(island_removal_mode 0)
		)
		(polygon
			(pts
				(xy 438.168796 -11.992356) (xy 438.344056 -11.992356) (xy 438.371996 -11.964416) (xy 438.371996 -10.569956)
				(xy 438.349136 -10.547096) (xy 438.178956 -10.547096) (xy 438.158636 -10.567416) (xy 438.158636 -11.982196)
			)
		)
	)
	(zone
		(layer "F.Cu")
		(hatch none 0.5)
		(connect_pads
			(clearance 0)
		)
		(min_thickness 0.25)
		(keepout
			(tracks allowed)
			(vias allowed)
			(pads allowed)
			(copperpour allowed)
			(footprints allowed)
		)
		(placement
			(enabled no)
			(sheetname "")
		)
		(fill
			(thermal_gap 0.5)
			(thermal_bridge_width 0.5)
			(island_removal_mode 0)
		)
		(polygon
			(pts
				(xy 180.423058 -217.40495) (xy 180.423058 -217.17635) (xy 182.455058 -217.17635) (xy 182.455058 -217.40495)
			)
		)
	)
	(zone
		(layer "F.Cu")
		(hatch none 0.5)
		(connect_pads
			(clearance 0)
		)
		(min_thickness 0.25)
		(keepout
			(tracks allowed)
			(vias allowed)
			(pads allowed)
			(copperpour allowed)
			(footprints allowed)
		)
		(placement
			(enabled no)
			(sheetname "")
		)
		(fill
			(thermal_gap 0.5)
			(thermal_bridge_width 0.5)
			(island_removal_mode 0)
		)
		(polygon
			(pts
				(xy 304.319178 -248.116598) (xy 304.319178 -247.67286) (xy 306.644294 -247.67286) (xy 306.644294 -248.116598)
			)
		)
	)
	(zone
		(layer "F.Cu")
		(hatch none 0.5)
		(connect_pads
			(clearance 0)
		)
		(min_thickness 0.25)
		(keepout
			(tracks allowed)
			(vias allowed)
			(pads allowed)
			(copperpour allowed)
			(footprints allowed)
		)
		(placement
			(enabled no)
			(sheetname "")
		)
		(fill
			(thermal_gap 0.5)
			(thermal_bridge_width 0.5)
			(island_removal_mode 0)
		)
		(polygon
			(pts
				(xy 387.70306 -271.975834) (xy 389.37946 -273.652234) (xy 389.400796 -273.67357) (xy 389.400796 -273.790918)
				(xy 389.2423 -273.949414) (xy 389.14705 -273.949414) (xy 388.302246 -273.10461) (xy 388.282434 -273.10461)
				(xy 388.127748 -273.259296) (xy 388.127748 -273.30908) (xy 388.946898 -274.12823) (xy 388.946898 -274.258786)
				(xy 388.546086 -274.659598) (xy 388.546086 -274.812252) (xy 388.060184 -275.298154) (xy 388.060184 -275.313648)
				(xy 388.252462 -275.505926) (xy 388.252462 -275.585428) (xy 387.841998 -275.995892) (xy 387.841998 -276.023578)
				(xy 387.841998 -276.206204) (xy 388.07009 -276.434296) (xy 388.07009 -276.51202) (xy 387.570472 -277.011638)
				(xy 387.570472 -277.161498) (xy 387.130798 -277.601172) (xy 387.284214 -277.754588) (xy 387.57479 -278.045418)
				(xy 387.57479 -278.654002) (xy 387.677406 -278.756618) (xy 387.677406 -279.357074) (xy 387.892798 -279.572212)
				(xy 387.892798 -280.115772) (xy 388.070344 -280.293318) (xy 388.070344 -281.069288) (xy 387.961124 -281.178508)
				(xy 386.816092 -281.178508) (xy 386.816092 -286.272224) (xy 386.803392 -286.284924) (xy 386.803646 -291.326824)
				(xy 386.745988 -291.384482) (xy 386.745988 -296.768012) (xy 386.618226 -296.895774) (xy 386.618226 -296.999152)
				(xy 387.027166 -297.408092) (xy 387.114288 -297.408092) (xy 388.78891 -297.408092) (xy 388.934706 -297.408092)
				(xy 390.832086 -295.510712) (xy 390.832086 -295.479724) (xy 390.784334 -295.431972) (xy 390.711182 -295.35882)
				(xy 390.550654 -295.198292) (xy 390.550654 -295.162732) (xy 391.497566 -294.21582) (xy 391.497566 -294.118284)
				(xy 391.406634 -294.027352) (xy 391.19556 -293.816278) (xy 391.627106 -293.384732) (xy 391.627106 -292.886892)
				(xy 391.545826 -292.805612) (xy 392.673586 -291.677852) (xy 392.698986 -291.677852) (xy 393.237466 -291.139372)
				(xy 393.237466 -291.104828) (xy 393.16152 -291.028882) (xy 392.78052 -290.647882) (xy 392.409934 -290.277296)
				(xy 392.288268 -290.15563) (xy 393.034266 -289.409632) (xy 393.034266 -289.054032) (xy 393.596114 -288.492184)
				(xy 393.596114 -288.401252) (xy 393.596114 -288.220912) (xy 393.826746 -287.99028) (xy 393.826746 -287.674812)
				(xy 394.180314 -287.321244) (xy 394.180314 -286.936434) (xy 394.180314 -285.971234) (xy 394.332714 -285.818834)
				(xy 394.485114 -285.818834) (xy 394.587984 -285.818834) (xy 397.321786 -283.085032) (xy 397.321786 -282.98013)
				(xy 397.284702 -282.943046) (xy 396.79753 -282.455874) (xy 396.79753 -282.407868) (xy 397.414496 -281.790902)
				(xy 398.142714 -281.062684) (xy 398.627346 -280.578052) (xy 398.627346 -280.184352) (xy 398.447514 -280.00452)
				(xy 398.447514 -279.973532) (xy 398.596866 -279.82418) (xy 398.596866 -279.214834) (xy 398.850866 -278.960834)
				(xy 399.006314 -278.960834) (xy 399.139664 -278.960834) (xy 399.469102 -278.631396) (xy 399.469102 -278.498046)
				(xy 399.294604 -278.323294) (xy 399.294604 -277.454868) (xy 400.276314 -277.454868) (xy 400.400266 -277.454868)
				(xy 400.400266 -274.3962) (xy 400.609054 -274.187412) (xy 401.24126 -274.187412) (xy 401.357846 -274.187412)
				(xy 401.357846 -273.427952) (xy 401.152614 -273.427952) (xy 400.47164 -273.427952) (xy 399.99666 -272.952972)
				(xy 399.99666 -272.856452) (xy 400.382486 -272.470626) (xy 400.382486 -272.03146) (xy 400.22526 -271.874234)
				(xy 400.00936 -271.658334) (xy 400.25066 -271.417034) (xy 400.25066 -271.251172) (xy 400.418046 -271.083786)
				(xy 400.418046 -271.075912) (xy 400.251168 -270.909034) (xy 400.25066 -270.909034) (xy 399.095722 -269.754096)
				(xy 399.095722 -268.023848) (xy 398.967706 -267.895832) (xy 398.787366 -267.895832) (xy 398.380204 -267.895832)
				(xy 390.162796 -259.678424) (xy 390.066276 -259.678424) (xy 389.174736 -260.56971) (xy 389.174736 -260.595618)
				(xy 390.37641 -261.797292) (xy 390.37641 -261.880858) (xy 389.9662 -262.291068) (xy 389.900668 -262.291068)
				(xy 389.66267 -262.05307) (xy 389.66267 -262.052308) (xy 389.661908 -262.052308) (xy 389.263382 -261.653782)
				(xy 389.224266 -261.653782) (xy 388.92861 -261.949438) (xy 388.92861 -262.025638) (xy 389.02767 -262.124698)
				(xy 389.02767 -262.259826) (xy 388.990332 -262.297164) (xy 388.19328 -263.094216) (xy 388.19328 -263.254744)
				(xy 389.311642 -264.373106) (xy 389.311642 -264.537952) (xy 388.716774 -265.13282) (xy 388.558024 -265.13282)
				(xy 388.082028 -264.656824) (xy 388.018782 -264.656824) (xy 387.887718 -264.787888) (xy 387.887718 -264.859262)
				(xy 389.08355 -266.055094) (xy 389.08355 -266.261088) (xy 388.359904 -266.984734) (xy 388.359904 -267.028676)
				(xy 388.598664 -267.267436) (xy 388.598664 -267.32103) (xy 388.39013 -267.529564) (xy 388.258812 -267.529564)
				(xy 388.054596 -267.325348) (xy 388.03326 -267.325348) (xy 387.310884 -268.047724) (xy 387.310884 -268.095476)
				(xy 389.107426 -269.892018) (xy 389.107426 -270.023082) (xy 388.770114 -270.360394) (xy 388.770114 -270.425672)
				(xy 388.863332 -270.51889) (xy 388.863332 -270.774668) (xy 388.141972 -271.496028) (xy 388.104634 -271.496028)
				(xy 388.049516 -271.44091) (xy 388.036054 -271.427448) (xy 387.898132 -271.427448) (xy 387.5786 -271.74698)
				(xy 387.5786 -271.85112) (xy 387.625336 -271.897856) (xy 387.68274 -271.95526)
			)
		)
	)
	(zone
		(layer "F.Cu")
		(hatch none 0.5)
		(connect_pads
			(clearance 0)
		)
		(min_thickness 0.25)
		(keepout
			(tracks allowed)
			(vias allowed)
			(pads allowed)
			(copperpour allowed)
			(footprints not_allowed)
		)
		(placement
			(enabled no)
			(sheetname "")
		)
		(fill
			(thermal_gap 0.5)
			(thermal_bridge_width 0.5)
			(island_removal_mode 0)
		)
		(polygon
			(pts
				(arc
					(start 456.460098 -347.700092)
					(mid 461.460088 -342.700102)
					(end 466.460078 -347.700092)
				)
				(arc
					(start 466.460078 -347.700092)
					(mid 461.460088 -352.700082)
					(end 456.460098 -347.700092)
				)
			)
		)
	)
	(zone
		(layer "F.Cu")
		(hatch none 0.5)
		(connect_pads
			(clearance 0)
		)
		(min_thickness 0.25)
		(keepout
			(tracks allowed)
			(vias allowed)
			(pads allowed)
			(copperpour allowed)
			(footprints allowed)
		)
		(placement
			(enabled no)
			(sheetname "")
		)
		(fill
			(thermal_gap 0.5)
			(thermal_bridge_width 0.5)
			(island_removal_mode 0)
		)
		(polygon
			(pts
				(xy 180.423058 -283.704792) (xy 180.423058 -283.476192) (xy 182.455058 -283.476192) (xy 182.455058 -283.704792)
			)
		)
	)
	(zone
		(layer "F.Cu")
		(hatch none 0.5)
		(connect_pads
			(clearance 0)
		)
		(min_thickness 0.25)
		(keepout
			(tracks allowed)
			(vias allowed)
			(pads allowed)
			(copperpour allowed)
			(footprints allowed)
		)
		(placement
			(enabled no)
			(sheetname "")
		)
		(fill
			(thermal_gap 0.5)
			(thermal_bridge_width 0.5)
			(island_removal_mode 0)
		)
		(polygon
			(pts
				(xy 124.107448 -410.948886) (xy 124.107448 -406.105868) (xy 125.991874 -406.105868) (xy 125.991874 -410.948886)
			)
		)
	)
	(zone
		(layer "F.Cu")
		(hatch none 0.5)
		(connect_pads
			(clearance 0)
		)
		(min_thickness 0.25)
		(keepout
			(tracks allowed)
			(vias allowed)
			(pads allowed)
			(copperpour allowed)
			(footprints allowed)
		)
		(placement
			(enabled no)
			(sheetname "")
		)
		(fill
			(thermal_gap 0.5)
			(thermal_bridge_width 0.5)
			(island_removal_mode 0)
		)
		(polygon
			(pts
				(xy 192.066926 -216.326466) (xy 194.098926 -216.326466) (xy 194.098926 -216.555066) (xy 192.066926 -216.555066)
				(xy 191.930782 -216.555066) (xy 191.883792 -216.555066) (xy 191.883792 -216.326466) (xy 191.930782 -216.326466)
			)
		)
	)
	(zone
		(layer "F.Cu")
		(hatch none 0.5)
		(connect_pads
			(clearance 0)
		)
		(min_thickness 0.25)
		(keepout
			(tracks allowed)
			(vias allowed)
			(pads allowed)
			(copperpour allowed)
			(footprints allowed)
		)
		(placement
			(enabled no)
			(sheetname "")
		)
		(fill
			(thermal_gap 0.5)
			(thermal_bridge_width 0.5)
			(island_removal_mode 0)
		)
		(polygon
			(pts
				(xy 409.831794 -248.004838) (xy 409.831794 -247.776238) (xy 411.863794 -247.776238) (xy 411.863794 -248.004838)
			)
		)
	)
	(zone
		(layer "F.Cu")
		(hatch none 0.5)
		(connect_pads
			(clearance 0)
		)
		(min_thickness 0.25)
		(keepout
			(tracks allowed)
			(vias allowed)
			(pads allowed)
			(copperpour allowed)
			(footprints allowed)
		)
		(placement
			(enabled no)
			(sheetname "")
		)
		(fill
			(thermal_gap 0.5)
			(thermal_bridge_width 0.5)
			(island_removal_mode 0)
		)
		(polygon
			(pts
				(xy 195.510658 -301.554896) (xy 195.510658 -301.326296) (xy 197.542658 -301.326296) (xy 197.542658 -301.554896)
			)
		)
	)
	(zone
		(layer "F.Cu")
		(hatch none 0.5)
		(connect_pads
			(clearance 0)
		)
		(min_thickness 0.25)
		(keepout
			(tracks allowed)
			(vias allowed)
			(pads allowed)
			(copperpour allowed)
			(footprints allowed)
		)
		(placement
			(enabled no)
			(sheetname "")
		)
		(fill
			(thermal_gap 0.5)
			(thermal_bridge_width 0.5)
			(island_removal_mode 0)
		)
		(polygon
			(pts
				(xy 180.423058 -226.754944) (xy 180.423058 -226.526344) (xy 182.455058 -226.526344) (xy 182.455058 -226.754944)
			)
		)
	)
	(zone
		(layer "F.Cu")
		(hatch none 0.5)
		(connect_pads
			(clearance 0)
		)
		(min_thickness 0.25)
		(keepout
			(tracks allowed)
			(vias allowed)
			(pads allowed)
			(copperpour allowed)
			(footprints allowed)
		)
		(placement
			(enabled no)
			(sheetname "")
		)
		(fill
			(thermal_gap 0.5)
			(thermal_bridge_width 0.5)
			(island_removal_mode 0)
		)
		(polygon
			(pts
				(xy 311.89168 -288.06648) (xy 311.89168 -287.622742) (xy 314.17768 -287.622742) (xy 314.17768 -288.06648)
			)
		)
	)
	(zone
		(layer "F.Cu")
		(hatch none 0.5)
		(connect_pads
			(clearance 0)
		)
		(min_thickness 0.25)
		(keepout
			(tracks allowed)
			(vias allowed)
			(pads allowed)
			(copperpour allowed)
			(footprints allowed)
		)
		(placement
			(enabled no)
			(sheetname "")
		)
		(fill
			(thermal_gap 0.5)
			(thermal_bridge_width 0.5)
			(island_removal_mode 0)
		)
		(polygon
			(pts
				(xy 56.926226 -162.581082) (xy 52.920646 -162.581082) (xy 52.440586 -163.061142) (xy 52.440586 -165.126162)
				(xy 52.712366 -165.397942) (xy 54.566566 -165.397942) (xy 54.818026 -165.649402) (xy 54.818026 -167.569642)
				(xy 55.234586 -167.986202) (xy 56.725566 -167.986202) (xy 57.373266 -167.338502) (xy 57.373266 -163.028122)
			)
		)
	)
	(zone
		(layer "F.Cu")
		(hatch none 0.5)
		(connect_pads
			(clearance 0)
		)
		(min_thickness 0.25)
		(keepout
			(tracks allowed)
			(vias allowed)
			(pads allowed)
			(copperpour allowed)
			(footprints allowed)
		)
		(placement
			(enabled no)
			(sheetname "")
		)
		(fill
			(thermal_gap 0.5)
			(thermal_bridge_width 0.5)
			(island_removal_mode 0)
		)
		(polygon
			(pts
				(xy 171.75988 -364.465108) (xy 171.75988 -362.067348) (xy 172.7835 -362.067348) (xy 172.7835 -364.465108)
			)
		)
	)
	(zone
		(layer "F.Cu")
		(hatch none 0.5)
		(connect_pads
			(clearance 0)
		)
		(min_thickness 0.25)
		(keepout
			(tracks allowed)
			(vias allowed)
			(pads allowed)
			(copperpour allowed)
			(footprints allowed)
		)
		(placement
			(enabled no)
			(sheetname "")
		)
		(fill
			(thermal_gap 0.5)
			(thermal_bridge_width 0.5)
			(island_removal_mode 0)
		)
		(polygon
			(pts
				(xy 259.056378 -250.666504) (xy 259.056378 -250.222766) (xy 261.381494 -250.222766) (xy 261.381494 -250.666504)
			)
		)
	)
	(zone
		(layer "F.Cu")
		(hatch none 0.5)
		(connect_pads
			(clearance 0)
		)
		(min_thickness 0.25)
		(keepout
			(tracks allowed)
			(vias allowed)
			(pads allowed)
			(copperpour allowed)
			(footprints allowed)
		)
		(placement
			(enabled no)
			(sheetname "")
		)
		(fill
			(thermal_gap 0.5)
			(thermal_bridge_width 0.5)
			(island_removal_mode 0)
		)
		(polygon
			(pts
				(xy 207.154526 -235.026454) (xy 209.186526 -235.026454) (xy 209.186526 -235.255054) (xy 207.154526 -235.255054)
				(xy 207.018382 -235.255054) (xy 206.971392 -235.255054) (xy 206.971392 -235.026454) (xy 207.018382 -235.026454)
			)
		)
	)
	(zone
		(layer "F.Cu")
		(hatch none 0.5)
		(connect_pads
			(clearance 0)
		)
		(min_thickness 0.25)
		(keepout
			(tracks allowed)
			(vias allowed)
			(pads allowed)
			(copperpour allowed)
			(footprints allowed)
		)
		(placement
			(enabled no)
			(sheetname "")
		)
		(fill
			(thermal_gap 0.5)
			(thermal_bridge_width 0.5)
			(island_removal_mode 0)
		)
		(polygon
			(pts
				(xy 443.450726 -311.755028) (xy 443.450726 -311.526428) (xy 445.482726 -311.526428) (xy 445.482726 -311.755028)
			)
		)
	)
	(zone
		(layer "F.Cu")
		(hatch none 0.5)
		(connect_pads
			(clearance 0)
		)
		(min_thickness 0.25)
		(keepout
			(tracks allowed)
			(vias allowed)
			(pads allowed)
			(copperpour allowed)
			(footprints allowed)
		)
		(placement
			(enabled no)
			(sheetname "")
		)
		(fill
			(thermal_gap 0.5)
			(thermal_bridge_width 0.5)
			(island_removal_mode 0)
		)
		(polygon
			(pts
				(xy 14.560042 -265.966448) (xy 14.560042 -265.52271) (xy 16.885158 -265.52271) (xy 16.885158 -265.966448)
			)
		)
	)
	(zone
		(layer "F.Cu")
		(hatch none 0.5)
		(connect_pads
			(clearance 0)
		)
		(min_thickness 0.25)
		(keepout
			(tracks allowed)
			(vias allowed)
			(pads allowed)
			(copperpour allowed)
			(footprints allowed)
		)
		(placement
			(enabled no)
			(sheetname "")
		)
		(fill
			(thermal_gap 0.5)
			(thermal_bridge_width 0.5)
			(island_removal_mode 0)
		)
		(polygon
			(pts
				(xy 210.30692 -392.869928) (xy 210.30692 -391.693908) (xy 211.90966 -391.693908) (xy 211.90966 -392.869928)
			)
		)
	)
	(zone
		(layer "F.Cu")
		(hatch none 0.5)
		(connect_pads
			(clearance 0)
		)
		(min_thickness 0.25)
		(keepout
			(tracks allowed)
			(vias allowed)
			(pads allowed)
			(copperpour allowed)
			(footprints not_allowed)
		)
		(placement
			(enabled no)
			(sheetname "")
		)
		(fill
			(thermal_gap 0.5)
			(thermal_bridge_width 0.5)
			(island_removal_mode 0)
		)
		(polygon
			(pts
				(arc
					(start 7.20598 -167.860472)
					(mid 17.770114 -157.53567)
					(end 2.999994 -157.318202)
				)
				(arc
					(start 2.999994 -163.681918)
					(mid 3.756989 -165.045828)
					(end 4.764278 -166.236904)
				)
				(xy 7.20598 -166.236904)
			)
		)
	)
	(zone
		(layer "F.Cu")
		(hatch none 0.5)
		(connect_pads
			(clearance 0)
		)
		(min_thickness 0.25)
		(keepout
			(tracks allowed)
			(vias allowed)
			(pads allowed)
			(copperpour allowed)
			(footprints allowed)
		)
		(placement
			(enabled no)
			(sheetname "")
		)
		(fill
			(thermal_gap 0.5)
			(thermal_bridge_width 0.5)
			(island_removal_mode 0)
		)
		(polygon
			(pts
				(xy 59.822842 -250.666504) (xy 59.822842 -250.222766) (xy 62.147958 -250.222766) (xy 62.147958 -250.666504)
			)
		)
	)
	(zone
		(layer "F.Cu")
		(hatch none 0.5)
		(connect_pads
			(clearance 0)
		)
		(min_thickness 0.25)
		(keepout
			(tracks allowed)
			(vias allowed)
			(pads allowed)
			(copperpour allowed)
			(footprints allowed)
		)
		(placement
			(enabled no)
			(sheetname "")
		)
		(fill
			(thermal_gap 0.5)
			(thermal_bridge_width 0.5)
			(island_removal_mode 0)
		)
		(polygon
			(pts
				(xy 176.979326 -272.42643) (xy 179.011326 -272.42643) (xy 179.011326 -272.65503) (xy 176.979326 -272.65503)
				(xy 176.843182 -272.65503) (xy 176.796192 -272.65503) (xy 176.796192 -272.42643) (xy 176.843182 -272.42643)
			)
		)
	)
	(zone
		(layer "F.Cu")
		(hatch none 0.5)
		(connect_pads
			(clearance 0)
		)
		(min_thickness 0.25)
		(keepout
			(tracks allowed)
			(vias allowed)
			(pads allowed)
			(copperpour allowed)
			(footprints allowed)
		)
		(placement
			(enabled no)
			(sheetname "")
		)
		(fill
			(thermal_gap 0.5)
			(thermal_bridge_width 0.5)
			(island_removal_mode 0)
		)
		(polygon
			(pts
				(xy 56.379364 -210.716368) (xy 56.379364 -210.27263) (xy 58.70448 -210.27263) (xy 58.70448 -210.716368)
			)
		)
	)
	(zone
		(layer "F.Cu")
		(hatch none 0.5)
		(connect_pads
			(clearance 0)
		)
		(min_thickness 0.25)
		(keepout
			(tracks allowed)
			(vias allowed)
			(pads allowed)
			(copperpour allowed)
			(footprints allowed)
		)
		(placement
			(enabled no)
			(sheetname "")
		)
		(fill
			(thermal_gap 0.5)
			(thermal_bridge_width 0.5)
			(island_removal_mode 0)
		)
		(polygon
			(pts
				(xy 29.647642 -230.266494) (xy 29.647642 -229.822756) (xy 31.972758 -229.822756) (xy 31.972758 -230.266494)
			)
		)
	)
	(zone
		(layer "F.Cu")
		(hatch none 0.5)
		(connect_pads
			(clearance 0)
		)
		(min_thickness 0.25)
		(keepout
			(tracks allowed)
			(vias allowed)
			(pads allowed)
			(copperpour allowed)
			(footprints allowed)
		)
		(placement
			(enabled no)
			(sheetname "")
		)
		(fill
			(thermal_gap 0.5)
			(thermal_bridge_width 0.5)
			(island_removal_mode 0)
		)
		(polygon
			(pts
				(xy 210.598258 -310.90489) (xy 210.598258 -310.67629) (xy 212.630258 -310.67629) (xy 212.630258 -310.90489)
			)
		)
	)
	(zone
		(layer "F.Cu")
		(hatch none 0.5)
		(connect_pads
			(clearance 0)
		)
		(min_thickness 0.25)
		(keepout
			(tracks allowed)
			(vias allowed)
			(pads allowed)
			(copperpour allowed)
			(footprints allowed)
		)
		(placement
			(enabled no)
			(sheetname "")
		)
		(fill
			(thermal_gap 0.5)
			(thermal_bridge_width 0.5)
			(island_removal_mode 0)
		)
		(polygon
			(pts
				(xy 11.11631 -211.566506) (xy 11.11631 -211.122768) (xy 13.441426 -211.122768) (xy 13.441426 -211.566506)
			)
		)
	)
	(zone
		(layer "F.Cu")
		(hatch none 0.5)
		(connect_pads
			(clearance 0)
		)
		(min_thickness 0.25)
		(keepout
			(tracks allowed)
			(vias allowed)
			(pads allowed)
			(copperpour allowed)
			(footprints allowed)
		)
		(placement
			(enabled no)
			(sheetname "")
		)
		(fill
			(thermal_gap 0.5)
			(thermal_bridge_width 0.5)
			(island_removal_mode 0)
		)
		(polygon
			(pts
				(xy 262.50011 -211.566506) (xy 262.50011 -211.122768) (xy 264.825226 -211.122768) (xy 264.825226 -211.566506)
			)
		)
	)
	(zone
		(layer "F.Cu")
		(hatch none 0.5)
		(connect_pads
			(clearance 0)
		)
		(min_thickness 0.25)
		(keepout
			(tracks allowed)
			(vias allowed)
			(pads allowed)
			(copperpour allowed)
			(footprints allowed)
		)
		(placement
			(enabled no)
			(sheetname "")
		)
		(fill
			(thermal_gap 0.5)
			(thermal_bridge_width 0.5)
			(island_removal_mode 0)
		)
		(polygon
			(pts
				(xy 192.066926 -239.276382) (xy 194.098926 -239.276382) (xy 194.098926 -239.278668) (xy 194.277742 -239.278668)
				(xy 194.277742 -239.515904) (xy 194.415664 -239.515904) (xy 194.458844 -239.559084) (xy 194.458844 -239.691926)
				(xy 194.458844 -239.995964) (xy 194.3862 -240.068608) (xy 191.845946 -240.068608) (xy 191.704722 -239.927384)
				(xy 191.704722 -239.73028) (xy 191.786256 -239.648746) (xy 191.786256 -239.276382) (xy 191.883792 -239.276382)
				(xy 191.930782 -239.276382)
			)
		)
	)
	(zone
		(layer "F.Cu")
		(hatch none 0.5)
		(connect_pads
			(clearance 0)
		)
		(min_thickness 0.25)
		(keepout
			(tracks allowed)
			(vias allowed)
			(pads allowed)
			(copperpour allowed)
			(footprints allowed)
		)
		(placement
			(enabled no)
			(sheetname "")
		)
		(fill
			(thermal_gap 0.5)
			(thermal_bridge_width 0.5)
			(island_removal_mode 0)
		)
		(polygon
			(pts
				(xy 409.831794 -276.676358) (xy 411.863794 -276.676358) (xy 411.863794 -276.678644) (xy 412.04261 -276.678644)
				(xy 412.04261 -276.91588) (xy 412.180532 -276.91588) (xy 412.223712 -276.95906) (xy 412.223712 -277.091902)
				(xy 412.223712 -277.39594) (xy 412.151068 -277.468584) (xy 409.610814 -277.468584) (xy 409.46959 -277.32736)
				(xy 409.46959 -277.130256) (xy 409.551124 -277.048722) (xy 409.551124 -276.676358) (xy 409.64866 -276.676358)
				(xy 409.69565 -276.676358)
			)
		)
	)
	(zone
		(layer "F.Cu")
		(hatch none 0.5)
		(connect_pads
			(clearance 0)
		)
		(min_thickness 0.25)
		(keepout
			(tracks allowed)
			(vias allowed)
			(pads allowed)
			(copperpour allowed)
			(footprints allowed)
		)
		(placement
			(enabled no)
			(sheetname "")
		)
		(fill
			(thermal_gap 0.5)
			(thermal_bridge_width 0.5)
			(island_removal_mode 0)
		)
		(polygon
			(pts
				(xy 386.207 -220.939868) (xy 386.49402 -220.939868) (xy 386.5245 -220.909388) (xy 386.5245 -220.282008)
				(xy 386.43814 -220.195648) (xy 386.25018 -220.195648) (xy 386.17652 -220.269308) (xy 386.17652 -220.909388)
			)
		)
	)
	(zone
		(layer "F.Cu")
		(hatch none 0.5)
		(connect_pads
			(clearance 0)
		)
		(min_thickness 0.25)
		(keepout
			(tracks allowed)
			(vias allowed)
			(pads allowed)
			(copperpour allowed)
			(footprints allowed)
		)
		(placement
			(enabled no)
			(sheetname "")
		)
		(fill
			(thermal_gap 0.5)
			(thermal_bridge_width 0.5)
			(island_removal_mode 0)
		)
		(polygon
			(pts
				(xy 167.367458 -233.555032) (xy 165.335458 -233.555032) (xy 165.132004 -233.555032) (xy 165.132004 -232.782872)
				(xy 167.588438 -232.782872) (xy 167.588438 -233.555032)
			)
		)
	)
	(zone
		(layer "F.Cu")
		(hatch none 0.5)
		(connect_pads
			(clearance 0)
		)
		(min_thickness 0.25)
		(keepout
			(tracks allowed)
			(vias allowed)
			(pads allowed)
			(copperpour allowed)
			(footprints allowed)
		)
		(placement
			(enabled no)
			(sheetname "")
		)
		(fill
			(thermal_gap 0.5)
			(thermal_bridge_width 0.5)
			(island_removal_mode 0)
		)
		(polygon
			(pts
				(xy 207.154526 -315.776356) (xy 209.186526 -315.776356) (xy 209.186526 -316.004956) (xy 207.154526 -316.004956)
				(xy 207.018382 -316.004956) (xy 206.971392 -316.004956) (xy 206.971392 -315.776356) (xy 207.018382 -315.776356)
			)
		)
	)
	(zone
		(layer "F.Cu")
		(hatch none 0.5)
		(connect_pads
			(clearance 0)
		)
		(min_thickness 0.25)
		(keepout
			(tracks allowed)
			(vias allowed)
			(pads allowed)
			(copperpour allowed)
			(footprints allowed)
		)
		(placement
			(enabled no)
			(sheetname "")
		)
		(fill
			(thermal_gap 0.5)
			(thermal_bridge_width 0.5)
			(island_removal_mode 0)
		)
		(polygon
			(pts
				(xy 259.056378 -235.36656) (xy 259.056378 -234.922822) (xy 261.381494 -234.922822) (xy 261.381494 -235.36656)
			)
		)
	)
	(zone
		(layer "F.Cu")
		(hatch none 0.5)
		(connect_pads
			(clearance 0)
		)
		(min_thickness 0.25)
		(keepout
			(tracks allowed)
			(vias allowed)
			(pads allowed)
			(copperpour allowed)
			(footprints allowed)
		)
		(placement
			(enabled no)
			(sheetname "")
		)
		(fill
			(thermal_gap 0.5)
			(thermal_bridge_width 0.5)
			(island_removal_mode 0)
		)
		(polygon
			(pts
				(xy 405.731726 -220.804994) (xy 405.731726 -220.576394) (xy 407.763726 -220.576394) (xy 407.763726 -220.804994)
			)
		)
	)
	(zone
		(layer "F.Cu")
		(hatch none 0.5)
		(connect_pads
			(clearance 0)
		)
		(min_thickness 0.25)
		(keepout
			(tracks allowed)
			(vias allowed)
			(pads allowed)
			(copperpour allowed)
			(footprints allowed)
		)
		(placement
			(enabled no)
			(sheetname "")
		)
		(fill
			(thermal_gap 0.5)
			(thermal_bridge_width 0.5)
			(island_removal_mode 0)
		)
		(polygon
			(pts
				(xy 165.335458 -280.305002) (xy 165.335458 -280.076402) (xy 167.367458 -280.076402) (xy 167.367458 -280.305002)
			)
		)
	)
	(zone
		(layer "F.Cu")
		(hatch none 0.5)
		(connect_pads
			(clearance 0)
		)
		(min_thickness 0.25)
		(keepout
			(tracks allowed)
			(vias allowed)
			(pads allowed)
			(copperpour allowed)
			(footprints allowed)
		)
		(placement
			(enabled no)
			(sheetname "")
		)
		(fill
			(thermal_gap 0.5)
			(thermal_bridge_width 0.5)
			(island_removal_mode 0)
		)
		(polygon
			(pts
				(xy 59.822842 -299.966634) (xy 59.822842 -299.522896) (xy 62.147958 -299.522896) (xy 62.147958 -299.966634)
			)
		)
	)
	(zone
		(layer "F.Cu")
		(hatch none 0.5)
		(connect_pads
			(clearance 0)
		)
		(min_thickness 0.25)
		(keepout
			(tracks allowed)
			(vias allowed)
			(pads allowed)
			(copperpour allowed)
			(footprints allowed)
		)
		(placement
			(enabled no)
			(sheetname "")
		)
		(fill
			(thermal_gap 0.5)
			(thermal_bridge_width 0.5)
			(island_removal_mode 0)
		)
		(polygon
			(pts
				(xy 176.979326 -229.07625) (xy 179.011326 -229.07625) (xy 179.011326 -229.30485) (xy 176.979326 -229.30485)
				(xy 176.848008 -229.30485) (xy 176.8221 -229.30485) (xy 176.8221 -229.07625) (xy 176.848008 -229.07625)
			)
		)
	)
	(zone
		(layer "F.Cu")
		(hatch none 0.5)
		(connect_pads
			(clearance 0)
		)
		(min_thickness 0.25)
		(keepout
			(tracks allowed)
			(vias allowed)
			(pads allowed)
			(copperpour allowed)
			(footprints allowed)
		)
		(placement
			(enabled no)
			(sheetname "")
		)
		(fill
			(thermal_gap 0.5)
			(thermal_bridge_width 0.5)
			(island_removal_mode 0)
		)
		(polygon
			(pts
				(xy 113.310416 -335.958942) (xy 111.562896 -335.958942) (xy 111.562896 -334.023462) (xy 113.310416 -334.023462)
			)
		)
	)
	(zone
		(layer "F.Cu")
		(hatch none 0.5)
		(connect_pads
			(clearance 0)
		)
		(min_thickness 0.25)
		(keepout
			(tracks not_allowed)
			(vias allowed)
			(pads allowed)
			(copperpour not_allowed)
			(footprints allowed)
		)
		(placement
			(enabled no)
			(sheetname "")
		)
		(fill
			(thermal_gap 0.5)
			(thermal_bridge_width 0.5)
			(island_removal_mode 0)
		)
		(polygon
			(pts
				(arc
					(start 241.649758 -352.49993)
					(mid 236.649768 -357.49992)
					(end 231.649778 -352.49993)
				)
				(arc
					(start 231.649778 -352.49993)
					(mid 236.649768 -347.49994)
					(end 241.649758 -352.49993)
				)
			)
		)
	)
	(zone
		(layer "F.Cu")
		(hatch none 0.5)
		(connect_pads
			(clearance 0)
		)
		(min_thickness 0.25)
		(keepout
			(tracks not_allowed)
			(vias allowed)
			(pads allowed)
			(copperpour not_allowed)
			(footprints allowed)
		)
		(placement
			(enabled no)
			(sheetname "")
		)
		(fill
			(thermal_gap 0.5)
			(thermal_bridge_width 0.5)
			(island_removal_mode 0)
		)
		(polygon
			(pts
				(xy 29.542486 -166.859204) (xy 29.694886 -166.859204) (xy 29.694886 -163.546028) (xy 29.542486 -163.546028)
			)
		)
	)
	(zone
		(layer "F.Cu")
		(hatch none 0.5)
		(connect_pads
			(clearance 0)
		)
		(min_thickness 0.25)
		(keepout
			(tracks allowed)
			(vias allowed)
			(pads allowed)
			(copperpour allowed)
			(footprints allowed)
		)
		(placement
			(enabled no)
			(sheetname "")
		)
		(fill
			(thermal_gap 0.5)
			(thermal_bridge_width 0.5)
			(island_removal_mode 0)
		)
		(polygon
			(pts
				(xy 440.006994 -289.426396) (xy 442.038994 -289.426396) (xy 442.038994 -289.654996) (xy 440.006994 -289.654996)
				(xy 439.87085 -289.654996) (xy 439.82386 -289.654996) (xy 439.82386 -289.426396) (xy 439.87085 -289.426396)
			)
		)
	)
	(zone
		(layer "F.Cu")
		(hatch none 0.5)
		(connect_pads
			(clearance 0)
		)
		(min_thickness 0.25)
		(keepout
			(tracks allowed)
			(vias allowed)
			(pads allowed)
			(copperpour allowed)
			(footprints allowed)
		)
		(placement
			(enabled no)
			(sheetname "")
		)
		(fill
			(thermal_gap 0.5)
			(thermal_bridge_width 0.5)
			(island_removal_mode 0)
		)
		(polygon
			(pts
				(xy 333.547974 -252.981968) (xy 334.29321 -252.981968) (xy 334.833722 -253.52248) (xy 334.833722 -253.868682)
				(xy 335.957926 -254.992886) (xy 335.95818 -268.515846) (xy 334.99171 -269.482316) (xy 334.99171 -270.280638)
				(xy 335.439766 -270.728694) (xy 335.439766 -271.084802) (xy 335.943448 -271.588484) (xy 335.943448 -273.424904)
				(xy 334.442308 -274.926044) (xy 334.442308 -275.3995) (xy 334.856836 -275.813774) (xy 335.87817 -275.813774)
				(xy 337.04149 -276.977094) (xy 337.603592 -276.977094) (xy 338.367878 -277.74138) (xy 338.367878 -278.07412)
				(xy 338.103718 -278.33828) (xy 336.54619 -278.33828) (xy 336.399886 -278.484584) (xy 336.399886 -278.849836)
				(xy 336.015584 -279.234138) (xy 335.149444 -279.234138) (xy 335.040986 -279.342596) (xy 334.51927 -279.342596)
				(xy 334.401668 -279.224994) (xy 334.141572 -279.224994) (xy 334.045306 -279.32126) (xy 334.045306 -279.65908)
				(xy 333.562198 -280.141934) (xy 333.473806 -280.141934) (xy 333.286354 -279.954482) (xy 333.286354 -279.8826)
				(xy 333.169514 -279.76576) (xy 332.894432 -279.76576) (xy 332.834234 -279.825958) (xy 332.6638 -279.825958)
				(xy 332.538324 -279.700482) (xy 332.50759 -279.700482) (xy 332.411832 -279.700482) (xy 332.005432 -279.294082)
				(xy 332.005432 -279.199848) (xy 332.183232 -279.022302) (xy 332.183232 -278.940768) (xy 331.832458 -278.589994)
				(xy 331.768958 -278.589994) (xy 331.596238 -278.762714) (xy 331.50556 -278.762714) (xy 330.525628 -277.782782)
				(xy 330.525628 -277.664164) (xy 332.59014 -275.599652) (xy 332.59014 -275.500338) (xy 331.727302 -274.6375)
				(xy 331.56525 -274.6375) (xy 331.18679 -274.25904) (xy 331.18679 -274.15871) (xy 331.407008 -273.938492)
				(xy 331.407008 -273.872198) (xy 331.085698 -273.550888) (xy 331.085698 -273.444716) (xy 331.239368 -273.291046)
				(xy 331.239368 -273.228816) (xy 331.043026 -273.032474) (xy 331.043026 -272.964148) (xy 332.267814 -271.73936)
				(xy 332.267814 -271.72158) (xy 332.116176 -271.569942) (xy 332.116176 -271.498314) (xy 332.564232 -271.050258)
				(xy 332.564232 -271.010634) (xy 332.145894 -270.592296) (xy 332.145894 -270.218662) (xy 331.533754 -269.606522)
				(xy 331.533754 -269.52067) (xy 331.891132 -269.163292) (xy 331.891132 -269.129764) (xy 331.738478 -268.97711)
				(xy 331.712316 -268.97711) (xy 331.162152 -269.527274) (xy 331.063092 -269.527274) (xy 330.69403 -269.158212)
				(xy 330.69403 -269.047468) (xy 331.328776 -268.412722) (xy 331.328776 -268.353286) (xy 330.963778 -267.988288)
				(xy 330.963778 -267.885164) (xy 331.271372 -267.57757) (xy 331.271372 -267.519912) (xy 331.112622 -267.361162)
				(xy 331.112622 -267.327888) (xy 331.18806 -267.25245) (xy 331.65796 -266.78255) (xy 331.929486 -266.511024)
				(xy 331.929486 -265.94181) (xy 331.713586 -265.72591) (xy 331.713586 -264.791952) (xy 331.636116 -264.714482)
				(xy 330.712064 -264.714482) (xy 330.474066 -264.476484) (xy 330.474066 -264.311892) (xy 330.541376 -264.244582)
				(xy 330.541376 -264.188702) (xy 330.394818 -264.042144) (xy 330.394818 -263.958832) (xy 330.491846 -263.861804)
				(xy 330.491846 -263.786366) (xy 330.35494 -263.64946) (xy 330.35494 -263.56437) (xy 330.497942 -263.421368)
				(xy 331.646022 -263.421368) (xy 331.685646 -263.381744) (xy 331.685646 -263.220962) (xy 331.64399 -263.179306)
				(xy 330.6445 -263.179306) (xy 330.54925 -263.084056) (xy 330.54925 -262.471662) (xy 330.640436 -262.380476)
				(xy 330.868528 -262.380476) (xy 330.896468 -262.352536) (xy 330.896468 -261.914132) (xy 330.856844 -261.874508)
				(xy 330.59497 -261.874508) (xy 330.539344 -261.818882) (xy 330.539344 -261.430262) (xy 330.614528 -261.355078)
				(xy 331.650086 -261.355078) (xy 331.673962 -261.378954) (xy 331.759052 -261.378954) (xy 331.872082 -261.265924)
				(xy 331.872082 -261.204456) (xy 331.790802 -261.123176) (xy 331.279246 -261.123176) (xy 331.21981 -261.06374)
				(xy 331.21981 -260.02234) (xy 331.31506 -259.92709) (xy 331.440282 -259.92709) (xy 331.61859 -259.748782)
				(xy 331.61859 -259.562092) (xy 331.67701 -259.503672) (xy 331.67701 -258.836922) (xy 331.56652 -258.726432)
				(xy 331.56652 -258.542028) (xy 331.60589 -258.502658) (xy 331.60589 -258.485132) (xy 331.479398 -258.358894)
				(xy 331.479398 -258.315206) (xy 331.514958 -258.279646) (xy 331.514958 -258.142486) (xy 331.423772 -258.0513)
				(xy 331.423772 -257.991102) (xy 331.493114 -257.92176) (xy 331.559154 -257.85572) (xy 331.736954 -257.67792)
				(xy 332.966822 -257.67792) (xy 333.061818 -257.582924) (xy 333.061818 -257.394964) (xy 332.91907 -257.252216)
				(xy 332.614524 -257.252216) (xy 332.529434 -257.167126) (xy 332.529434 -257.02006) (xy 332.509876 -257.000502)
				(xy 332.24724 -257.000502) (xy 332.125828 -256.87909) (xy 332.125828 -256.336038) (xy 330.731876 -254.942086)
				(xy 330.731876 -254.746252) (xy 330.781406 -254.696722) (xy 330.802742 -254.675386) (xy 332.211426 -253.266448)
				(xy 333.263494 -253.266448) (xy 333.332074 -253.197868)
			)
		)
	)
	(zone
		(layer "F.Cu")
		(hatch none 0.5)
		(connect_pads
			(clearance 0)
		)
		(min_thickness 0.25)
		(keepout
			(tracks allowed)
			(vias allowed)
			(pads allowed)
			(copperpour allowed)
			(footprints allowed)
		)
		(placement
			(enabled no)
			(sheetname "")
		)
		(fill
			(thermal_gap 0.5)
			(thermal_bridge_width 0.5)
			(island_removal_mode 0)
		)
		(polygon
			(pts
				(xy 225.5647 -396.446248) (xy 225.5647 -393.195048) (xy 228.96576 -393.195048) (xy 228.96576 -396.446248)
			)
		)
	)
	(zone
		(layer "F.Cu")
		(hatch none 0.5)
		(connect_pads
			(clearance 0)
		)
		(min_thickness 0.25)
		(keepout
			(tracks allowed)
			(vias allowed)
			(pads allowed)
			(copperpour allowed)
			(footprints allowed)
		)
		(placement
			(enabled no)
			(sheetname "")
		)
		(fill
			(thermal_gap 0.5)
			(thermal_bridge_width 0.5)
			(island_removal_mode 0)
		)
		(polygon
			(pts
				(xy 442.05017 -238.656876) (xy 440.01817 -238.656876) (xy 440.01817 -238.65459) (xy 439.839354 -238.65459)
				(xy 439.839354 -238.417354) (xy 439.702702 -238.280702) (xy 439.697114 -238.280702) (xy 439.658252 -238.24184)
				(xy 439.658252 -238.241332) (xy 439.658252 -238.01832) (xy 439.811922 -237.86465) (xy 442.27115 -237.86465)
				(xy 442.412374 -238.005874) (xy 442.412374 -238.202978) (xy 442.33084 -238.284512) (xy 442.24702 -238.368332)
				(xy 442.24702 -238.656876) (xy 442.233304 -238.656876) (xy 442.186314 -238.656876)
			)
		)
	)
	(zone
		(layer "F.Cu")
		(hatch none 0.5)
		(connect_pads
			(clearance 0)
		)
		(min_thickness 0.25)
		(keepout
			(tracks allowed)
			(vias allowed)
			(pads allowed)
			(copperpour allowed)
			(footprints allowed)
		)
		(placement
			(enabled no)
			(sheetname "")
		)
		(fill
			(thermal_gap 0.5)
			(thermal_bridge_width 0.5)
			(island_removal_mode 0)
		)
		(polygon
			(pts
				(xy 44.735242 -218.366594) (xy 44.735242 -217.922856) (xy 47.060358 -217.922856) (xy 47.060358 -218.366594)
			)
		)
	)
	(zone
		(layer "F.Cu")
		(hatch none 0.5)
		(connect_pads
			(clearance 0)
		)
		(min_thickness 0.25)
		(keepout
			(tracks not_allowed)
			(vias allowed)
			(pads allowed)
			(copperpour not_allowed)
			(footprints allowed)
		)
		(placement
			(enabled no)
			(sheetname "")
		)
		(fill
			(thermal_gap 0.5)
			(thermal_bridge_width 0.5)
			(island_removal_mode 0)
		)
		(polygon
			(pts
				(xy 437.568848 -9.0424) (xy 437.744108 -9.0424) (xy 437.772048 -9.01446) (xy 437.772048 -7.62) (xy 437.749188 -7.59714)
				(xy 437.579008 -7.59714) (xy 437.558688 -7.61746) (xy 437.558688 -9.03224)
			)
		)
	)
	(zone
		(layer "F.Cu")
		(hatch none 0.5)
		(connect_pads
			(clearance 0)
		)
		(min_thickness 0.25)
		(keepout
			(tracks allowed)
			(vias allowed)
			(pads allowed)
			(copperpour allowed)
			(footprints not_allowed)
		)
		(placement
			(enabled no)
			(sheetname "")
		)
		(fill
			(thermal_gap 0.5)
			(thermal_bridge_width 0.5)
			(island_removal_mode 0)
		)
		(polygon
			(pts
				(arc
					(start 215.674956 -360.764074)
					(mid 213.67496 -362.76407)
					(end 211.674964 -360.764074)
				)
				(arc
					(start 211.674964 -360.764074)
					(mid 213.67496 -358.764078)
					(end 215.674956 -360.764074)
				)
			)
		)
	)
	(zone
		(layer "F.Cu")
		(hatch none 0.5)
		(connect_pads
			(clearance 0)
		)
		(min_thickness 0.25)
		(keepout
			(tracks allowed)
			(vias allowed)
			(pads allowed)
			(copperpour allowed)
			(footprints allowed)
		)
		(placement
			(enabled no)
			(sheetname "")
		)
		(fill
			(thermal_gap 0.5)
			(thermal_bridge_width 0.5)
			(island_removal_mode 0)
		)
		(polygon
			(pts
				(xy 87.90432 -215.255348) (xy 88.19134 -215.255348) (xy 88.22182 -215.224868) (xy 88.22182 -214.597488)
				(xy 88.13546 -214.511128) (xy 87.9475 -214.511128) (xy 87.87384 -214.584788) (xy 87.87384 -215.224868)
			)
		)
	)
	(zone
		(layer "F.Cu")
		(hatch none 0.5)
		(connect_pads
			(clearance 0)
		)
		(min_thickness 0.25)
		(keepout
			(tracks allowed)
			(vias allowed)
			(pads allowed)
			(copperpour allowed)
			(footprints allowed)
		)
		(placement
			(enabled no)
			(sheetname "")
		)
		(fill
			(thermal_gap 0.5)
			(thermal_bridge_width 0.5)
			(island_removal_mode 0)
		)
		(polygon
			(pts
				(xy 337.218782 -404.802594) (xy 337.218782 -399.959576) (xy 339.103208 -399.959576) (xy 339.103208 -404.802594)
			)
		)
	)
	(zone
		(layer "F.Cu")
		(hatch none 0.5)
		(connect_pads
			(clearance 0)
		)
		(min_thickness 0.25)
		(keepout
			(tracks allowed)
			(vias allowed)
			(pads allowed)
			(copperpour allowed)
			(footprints allowed)
		)
		(placement
			(enabled no)
			(sheetname "")
		)
		(fill
			(thermal_gap 0.5)
			(thermal_bridge_width 0.5)
			(island_removal_mode 0)
		)
		(polygon
			(pts
				(xy 423.7355 -9.637268) (xy 423.7355 -5.867908) (xy 431.6984 -5.867908) (xy 431.6984 -9.637268)
			)
		)
	)
	(zone
		(layer "F.Cu")
		(hatch none 0.5)
		(connect_pads
			(clearance 0)
		)
		(min_thickness 0.25)
		(keepout
			(tracks allowed)
			(vias allowed)
			(pads allowed)
			(copperpour allowed)
			(footprints allowed)
		)
		(placement
			(enabled no)
			(sheetname "")
		)
		(fill
			(thermal_gap 0.5)
			(thermal_bridge_width 0.5)
			(island_removal_mode 0)
		)
		(polygon
			(pts
				(xy 138.077448 -404.802594) (xy 138.077448 -399.959576) (xy 139.961874 -399.959576) (xy 139.961874 -404.802594)
			)
		)
	)
	(zone
		(layer "F.Cu")
		(hatch none 0.5)
		(connect_pads
			(clearance 0)
		)
		(min_thickness 0.25)
		(keepout
			(tracks allowed)
			(vias allowed)
			(pads allowed)
			(copperpour allowed)
			(footprints allowed)
		)
		(placement
			(enabled no)
			(sheetname "")
		)
		(fill
			(thermal_gap 0.5)
			(thermal_bridge_width 0.5)
			(island_removal_mode 0)
		)
		(polygon
			(pts
				(xy 292.67531 -293.166546) (xy 292.67531 -292.722808) (xy 295.000426 -292.722808) (xy 295.000426 -293.166546)
			)
		)
	)
	(zone
		(layer "F.Cu")
		(hatch none 0.5)
		(connect_pads
			(clearance 0)
		)
		(min_thickness 0.25)
		(keepout
			(tracks allowed)
			(vias allowed)
			(pads allowed)
			(copperpour allowed)
			(footprints allowed)
		)
		(placement
			(enabled no)
			(sheetname "")
		)
		(fill
			(thermal_gap 0.5)
			(thermal_bridge_width 0.5)
			(island_removal_mode 0)
		)
		(polygon
			(pts
				(xy 443.450726 -226.754944) (xy 443.450726 -226.526344) (xy 445.482726 -226.526344) (xy 445.482726 -226.754944)
			)
		)
	)
	(zone
		(layer "F.Cu")
		(hatch none 0.5)
		(connect_pads
			(clearance 0)
		)
		(min_thickness 0.25)
		(keepout
			(tracks allowed)
			(vias allowed)
			(pads allowed)
			(copperpour allowed)
			(footprints not_allowed)
		)
		(placement
			(enabled no)
			(sheetname "")
		)
		(fill
			(thermal_gap 0.5)
			(thermal_bridge_width 0.5)
			(island_removal_mode 0)
		)
		(polygon
			(pts
				(xy 420.84117 -330.091796) (xy 426.94098 -330.091796) (xy 426.94098 -186.09183) (xy 420.84117 -186.09183)
			)
		)
	)
	(zone
		(layer "F.Cu")
		(hatch none 0.5)
		(connect_pads
			(clearance 0)
		)
		(min_thickness 0.25)
		(keepout
			(tracks allowed)
			(vias allowed)
			(pads allowed)
			(copperpour allowed)
			(footprints allowed)
		)
		(placement
			(enabled no)
			(sheetname "")
		)
		(fill
			(thermal_gap 0.5)
			(thermal_bridge_width 0.5)
			(island_removal_mode 0)
		)
		(polygon
			(pts
				(xy 171.139612 -352.746564) (xy 169.323512 -352.746564) (xy 169.323512 -351.367344) (xy 171.139612 -351.367344)
			)
		)
	)
	(zone
		(layer "F.Cu")
		(hatch none 0.5)
		(connect_pads
			(clearance 0)
		)
		(min_thickness 0.25)
		(keepout
			(tracks allowed)
			(vias allowed)
			(pads allowed)
			(copperpour allowed)
			(footprints allowed)
		)
		(placement
			(enabled no)
			(sheetname "")
		)
		(fill
			(thermal_gap 0.5)
			(thermal_bridge_width 0.5)
			(island_removal_mode 0)
		)
		(polygon
			(pts
				(xy 29.647642 -309.316628) (xy 29.647642 -308.87289) (xy 31.972758 -308.87289) (xy 31.972758 -309.316628)
			)
		)
	)
	(zone
		(layer "F.Cu")
		(hatch none 0.5)
		(connect_pads
			(clearance 0)
		)
		(min_thickness 0.25)
		(keepout
			(tracks allowed)
			(vias allowed)
			(pads allowed)
			(copperpour allowed)
			(footprints allowed)
		)
		(placement
			(enabled no)
			(sheetname "")
		)
		(fill
			(thermal_gap 0.5)
			(thermal_bridge_width 0.5)
			(island_removal_mode 0)
		)
		(polygon
			(pts
				(xy 292.67531 -302.51654) (xy 292.67531 -302.072802) (xy 295.000426 -302.072802) (xy 295.000426 -302.51654)
			)
		)
	)
	(zone
		(layer "F.Cu")
		(hatch none 0.5)
		(connect_pads
			(clearance 0)
		)
		(min_thickness 0.25)
		(keepout
			(tracks allowed)
			(vias allowed)
			(pads allowed)
			(copperpour allowed)
			(footprints allowed)
		)
		(placement
			(enabled no)
			(sheetname "")
		)
		(fill
			(thermal_gap 0.5)
			(thermal_bridge_width 0.5)
			(island_removal_mode 0)
		)
		(polygon
			(pts
				(xy 44.735242 -260.016498) (xy 44.735242 -259.57276) (xy 47.060358 -259.57276) (xy 47.060358 -260.016498)
			)
		)
	)
	(zone
		(layer "F.Cu")
		(hatch none 0.5)
		(connect_pads
			(clearance 0)
		)
		(min_thickness 0.25)
		(keepout
			(tracks allowed)
			(vias allowed)
			(pads allowed)
			(copperpour allowed)
			(footprints allowed)
		)
		(placement
			(enabled no)
			(sheetname "")
		)
		(fill
			(thermal_gap 0.5)
			(thermal_bridge_width 0.5)
			(island_removal_mode 0)
		)
		(polygon
			(pts
				(xy 49.30648 -9.195308) (xy 49.30648 -6.165088) (xy 58.95848 -6.165088) (xy 58.95848 -9.195308)
			)
		)
	)
	(zone
		(layer "F.Cu")
		(hatch none 0.5)
		(connect_pads
			(clearance 0)
		)
		(min_thickness 0.25)
		(keepout
			(tracks allowed)
			(vias allowed)
			(pads allowed)
			(copperpour allowed)
			(footprints allowed)
		)
		(placement
			(enabled no)
			(sheetname "")
		)
		(fill
			(thermal_gap 0.5)
			(thermal_bridge_width 0.5)
			(island_removal_mode 0)
		)
		(polygon
			(pts
				(xy 289.231578 -286.366458) (xy 289.231578 -285.92272) (xy 291.556694 -285.92272) (xy 291.556694 -286.366458)
			)
		)
	)
	(zone
		(layer "F.Cu")
		(hatch none 0.5)
		(connect_pads
			(clearance 0)
		)
		(min_thickness 0.25)
		(keepout
			(tracks allowed)
			(vias allowed)
			(pads allowed)
			(copperpour allowed)
			(footprints allowed)
		)
		(placement
			(enabled no)
			(sheetname "")
		)
		(fill
			(thermal_gap 0.5)
			(thermal_bridge_width 0.5)
			(island_removal_mode 0)
		)
		(polygon
			(pts
				(xy 289.231832 -220.066362) (xy 289.231832 -219.622624) (xy 291.556948 -219.622624) (xy 291.556948 -220.066362)
			)
		)
	)
	(zone
		(layer "F.Cu")
		(hatch none 0.5)
		(connect_pads
			(clearance 0)
		)
		(min_thickness 0.25)
		(keepout
			(tracks allowed)
			(vias allowed)
			(pads allowed)
			(copperpour allowed)
			(footprints allowed)
		)
		(placement
			(enabled no)
			(sheetname "")
		)
		(fill
			(thermal_gap 0.5)
			(thermal_bridge_width 0.5)
			(island_removal_mode 0)
		)
		(polygon
			(pts
				(xy 59.822842 -290.61664) (xy 59.822842 -290.172902) (xy 62.147958 -290.172902) (xy 62.147958 -290.61664)
			)
		)
	)
	(zone
		(layer "F.Cu")
		(hatch none 0.5)
		(connect_pads
			(clearance 0)
		)
		(min_thickness 0.25)
		(keepout
			(tracks allowed)
			(vias allowed)
			(pads allowed)
			(copperpour allowed)
			(footprints allowed)
		)
		(placement
			(enabled no)
			(sheetname "")
		)
		(fill
			(thermal_gap 0.5)
			(thermal_bridge_width 0.5)
			(island_removal_mode 0)
		)
		(polygon
			(pts
				(xy 304.319178 -219.216478) (xy 304.319178 -218.77274) (xy 306.644294 -218.77274) (xy 306.644294 -219.216478)
			)
		)
	)
	(zone
		(layer "F.Cu")
		(hatch none 0.5)
		(connect_pads
			(clearance 0)
		)
		(min_thickness 0.25)
		(keepout
			(tracks allowed)
			(vias allowed)
			(pads allowed)
			(copperpour allowed)
			(footprints allowed)
		)
		(placement
			(enabled no)
			(sheetname "")
		)
		(fill
			(thermal_gap 0.5)
			(thermal_bridge_width 0.5)
			(island_removal_mode 0)
		)
		(polygon
			(pts
				(xy 440.006994 -306.426362) (xy 442.038994 -306.426362) (xy 442.038994 -306.654962) (xy 440.006994 -306.654962)
				(xy 439.87085 -306.654962) (xy 439.82386 -306.654962) (xy 439.82386 -306.426362) (xy 439.87085 -306.426362)
			)
		)
	)
	(zone
		(layer "F.Cu")
		(hatch none 0.5)
		(connect_pads
			(clearance 0)
		)
		(min_thickness 0.25)
		(keepout
			(tracks allowed)
			(vias allowed)
			(pads allowed)
			(copperpour allowed)
			(footprints allowed)
		)
		(placement
			(enabled no)
			(sheetname "")
		)
		(fill
			(thermal_gap 0.5)
			(thermal_bridge_width 0.5)
			(island_removal_mode 0)
		)
		(polygon
			(pts
				(xy 428.363126 -245.454932) (xy 428.363126 -245.226332) (xy 430.395126 -245.226332) (xy 430.395126 -245.454932)
			)
		)
	)
	(zone
		(layer "F.Cu")
		(hatch none 0.5)
		(connect_pads
			(clearance 0)
		)
		(min_thickness 0.25)
		(keepout
			(tracks not_allowed)
			(vias allowed)
			(pads allowed)
			(copperpour not_allowed)
			(footprints allowed)
		)
		(placement
			(enabled no)
			(sheetname "")
		)
		(fill
			(thermal_gap 0.5)
			(thermal_bridge_width 0.5)
			(island_removal_mode 0)
		)
		(polygon
			(pts
				(arc
					(start 200.600056 -22.29993)
					(mid 203.400152 -19.499834)
					(end 206.199994 -22.29993)
				)
				(arc
					(start 206.199994 -22.29993)
					(mid 203.400152 -25.099772)
					(end 200.600056 -22.29993)
				)
			)
		)
	)
	(zone
		(layer "F.Cu")
		(hatch none 0.5)
		(connect_pads
			(clearance 0)
		)
		(min_thickness 0.25)
		(keepout
			(tracks allowed)
			(vias allowed)
			(pads allowed)
			(copperpour allowed)
			(footprints allowed)
		)
		(placement
			(enabled no)
			(sheetname "")
		)
		(fill
			(thermal_gap 0.5)
			(thermal_bridge_width 0.5)
			(island_removal_mode 0)
		)
		(polygon
			(pts
				(xy 124.59716 -360.472228) (xy 124.59716 -353.880928) (xy 121.07418 -353.880928) (xy 121.07418 -360.472228)
			)
		)
	)
	(zone
		(layer "F.Cu")
		(hatch none 0.5)
		(connect_pads
			(clearance 0)
		)
		(min_thickness 0.25)
		(keepout
			(tracks allowed)
			(vias allowed)
			(pads allowed)
			(copperpour allowed)
			(footprints allowed)
		)
		(placement
			(enabled no)
			(sheetname "")
		)
		(fill
			(thermal_gap 0.5)
			(thermal_bridge_width 0.5)
			(island_removal_mode 0)
		)
		(polygon
			(pts
				(xy 388.378446 -342.787478) (xy 384.842766 -342.787478) (xy 384.842766 -340.704678) (xy 388.378446 -340.704678)
			)
		)
	)
	(zone
		(layer "F.Cu")
		(hatch none 0.5)
		(connect_pads
			(clearance 0)
		)
		(min_thickness 0.25)
		(keepout
			(tracks allowed)
			(vias allowed)
			(pads allowed)
			(copperpour allowed)
			(footprints allowed)
		)
		(placement
			(enabled no)
			(sheetname "")
		)
		(fill
			(thermal_gap 0.5)
			(thermal_bridge_width 0.5)
			(island_removal_mode 0)
		)
		(polygon
			(pts
				(xy 176.979326 -270.726408) (xy 179.011326 -270.726408) (xy 179.011326 -270.955008) (xy 176.979326 -270.955008)
				(xy 176.843182 -270.955008) (xy 176.796192 -270.955008) (xy 176.796192 -270.726408) (xy 176.843182 -270.726408)
			)
		)
	)
	(zone
		(layer "F.Cu")
		(hatch none 0.5)
		(connect_pads
			(clearance 0)
		)
		(min_thickness 0.25)
		(keepout
			(tracks allowed)
			(vias allowed)
			(pads allowed)
			(copperpour allowed)
			(footprints allowed)
		)
		(placement
			(enabled no)
			(sheetname "")
		)
		(fill
			(thermal_gap 0.5)
			(thermal_bridge_width 0.5)
			(island_removal_mode 0)
		)
		(polygon
			(pts
				(xy 292.67531 -271.916652) (xy 292.67531 -271.472914) (xy 295.000426 -271.472914) (xy 295.000426 -271.916652)
			)
		)
	)
	(zone
		(layer "F.Cu")
		(hatch none 0.5)
		(connect_pads
			(clearance 0)
		)
		(min_thickness 0.25)
		(keepout
			(tracks allowed)
			(vias allowed)
			(pads allowed)
			(copperpour allowed)
			(footprints allowed)
		)
		(placement
			(enabled no)
			(sheetname "")
		)
		(fill
			(thermal_gap 0.5)
			(thermal_bridge_width 0.5)
			(island_removal_mode 0)
		)
		(polygon
			(pts
				(xy 292.67531 -209.0166) (xy 292.67531 -208.572862) (xy 295.000426 -208.572862) (xy 295.000426 -209.0166)
			)
		)
	)
	(zone
		(layer "F.Cu")
		(hatch none 0.5)
		(connect_pads
			(clearance 0)
		)
		(min_thickness 0.25)
		(keepout
			(tracks allowed)
			(vias allowed)
			(pads allowed)
			(copperpour allowed)
			(footprints allowed)
		)
		(placement
			(enabled no)
			(sheetname "")
		)
		(fill
			(thermal_gap 0.5)
			(thermal_bridge_width 0.5)
			(island_removal_mode 0)
		)
		(polygon
			(pts
				(xy 288.77768 -365.01832) (xy 287.03016 -365.01832) (xy 287.03016 -363.08284) (xy 288.77768 -363.08284)
			)
		)
	)
	(zone
		(layer "F.Cu")
		(hatch none 0.5)
		(connect_pads
			(clearance 0)
		)
		(min_thickness 0.25)
		(keepout
			(tracks allowed)
			(vias allowed)
			(pads allowed)
			(copperpour allowed)
			(footprints allowed)
		)
		(placement
			(enabled no)
			(sheetname "")
		)
		(fill
			(thermal_gap 0.5)
			(thermal_bridge_width 0.5)
			(island_removal_mode 0)
		)
		(polygon
			(pts
				(xy 424.919394 -306.426362) (xy 426.951394 -306.426362) (xy 426.951394 -306.654962) (xy 424.919394 -306.654962)
				(xy 424.78325 -306.654962) (xy 424.73626 -306.654962) (xy 424.73626 -306.426362) (xy 424.78325 -306.426362)
			)
		)
	)
	(zone
		(layer "F.Cu")
		(hatch none 0.5)
		(connect_pads
			(clearance 0)
		)
		(min_thickness 0.25)
		(keepout
			(tracks not_allowed)
			(vias allowed)
			(pads allowed)
			(copperpour not_allowed)
			(footprints allowed)
		)
		(placement
			(enabled no)
			(sheetname "")
		)
		(fill
			(thermal_gap 0.5)
			(thermal_bridge_width 0.5)
			(island_removal_mode 0)
		)
		(polygon
			(pts
				(xy 86.792816 -338.762848) (xy 87.035132 -338.762848) (xy 87.035132 -337.757008) (xy 86.792816 -337.757008)
			)
		)
	)
	(zone
		(layer "F.Cu")
		(hatch none 0.5)
		(connect_pads
			(clearance 0)
		)
		(min_thickness 0.25)
		(keepout
			(tracks allowed)
			(vias allowed)
			(pads allowed)
			(copperpour allowed)
			(footprints allowed)
		)
		(placement
			(enabled no)
			(sheetname "")
		)
		(fill
			(thermal_gap 0.5)
			(thermal_bridge_width 0.5)
			(island_removal_mode 0)
		)
		(polygon
			(pts
				(xy 428.363126 -297.304968) (xy 428.363126 -297.076368) (xy 430.395126 -297.076368) (xy 430.395126 -297.304968)
			)
		)
	)
	(zone
		(layer "F.Cu")
		(hatch none 0.5)
		(connect_pads
			(clearance 0)
		)
		(min_thickness 0.25)
		(keepout
			(tracks allowed)
			(vias allowed)
			(pads allowed)
			(copperpour allowed)
			(footprints allowed)
		)
		(placement
			(enabled no)
			(sheetname "")
		)
		(fill
			(thermal_gap 0.5)
			(thermal_bridge_width 0.5)
			(island_removal_mode 0)
		)
		(polygon
			(pts
				(xy 262.50011 -237.066582) (xy 262.50011 -236.622844) (xy 264.825226 -236.622844) (xy 264.825226 -237.066582)
			)
		)
	)
	(zone
		(layer "F.Cu")
		(hatch none 0.5)
		(connect_pads
			(clearance 0)
		)
		(min_thickness 0.25)
		(keepout
			(tracks allowed)
			(vias allowed)
			(pads allowed)
			(copperpour allowed)
			(footprints allowed)
		)
		(placement
			(enabled no)
			(sheetname "")
		)
		(fill
			(thermal_gap 0.5)
			(thermal_bridge_width 0.5)
			(island_removal_mode 0)
		)
		(polygon
			(pts
				(xy 262.500364 -274.466812) (xy 262.500364 -274.023074) (xy 264.82548 -274.023074) (xy 264.82548 -274.466812)
			)
		)
	)
	(zone
		(layer "F.Cu")
		(hatch none 0.5)
		(connect_pads
			(clearance 0)
		)
		(min_thickness 0.25)
		(keepout
			(tracks allowed)
			(vias allowed)
			(pads allowed)
			(copperpour allowed)
			(footprints allowed)
		)
		(placement
			(enabled no)
			(sheetname "")
		)
		(fill
			(thermal_gap 0.5)
			(thermal_bridge_width 0.5)
			(island_removal_mode 0)
		)
		(polygon
			(pts
				(xy 347.575886 -333.586582) (xy 344.040206 -333.586582) (xy 344.040206 -331.503782) (xy 347.575886 -331.503782)
			)
		)
	)
	(zone
		(layer "F.Cu")
		(hatch none 0.5)
		(connect_pads
			(clearance 0)
		)
		(min_thickness 0.25)
		(keepout
			(tracks allowed)
			(vias allowed)
			(pads allowed)
			(copperpour allowed)
			(footprints allowed)
		)
		(placement
			(enabled no)
			(sheetname "")
		)
		(fill
			(thermal_gap 0.5)
			(thermal_bridge_width 0.5)
			(island_removal_mode 0)
		)
		(polygon
			(pts
				(xy 180.423058 -300.705012) (xy 180.423058 -300.476412) (xy 182.455058 -300.476412) (xy 182.455058 -300.705012)
			)
		)
	)
	(zone
		(layer "F.Cu")
		(hatch none 0.5)
		(connect_pads
			(clearance 0)
		)
		(min_thickness 0.25)
		(keepout
			(tracks not_allowed)
			(vias allowed)
			(pads allowed)
			(copperpour not_allowed)
			(footprints allowed)
		)
		(placement
			(enabled no)
			(sheetname "")
		)
		(fill
			(thermal_gap 0.5)
			(thermal_bridge_width 0.5)
			(island_removal_mode 0)
		)
		(polygon
			(pts
				(xy 326.602598 -345.52128) (xy 330.51496 -345.52128) (xy 330.51496 -345.389708) (xy 330.46162 -345.336368)
				(xy 328.990452 -345.336368) (xy 328.990452 -343.177368) (xy 331.147166 -343.177368) (xy 331.147166 -342.927686)
				(xy 328.74204 -342.927686) (xy 328.74204 -343.251028) (xy 328.699114 -343.251028) (xy 328.699114 -345.280742)
				(xy 326.844914 -345.280742) (xy 326.844914 -345.039696) (xy 326.602598 -345.039696)
			)
		)
	)
	(zone
		(layer "F.Cu")
		(hatch none 0.5)
		(connect_pads
			(clearance 0)
		)
		(min_thickness 0.25)
		(keepout
			(tracks allowed)
			(vias allowed)
			(pads allowed)
			(copperpour allowed)
			(footprints allowed)
		)
		(placement
			(enabled no)
			(sheetname "")
		)
		(fill
			(thermal_gap 0.5)
			(thermal_bridge_width 0.5)
			(island_removal_mode 0)
		)
		(polygon
			(pts
				(xy 341.628222 -410.948886) (xy 341.628222 -406.105868) (xy 343.512648 -406.105868) (xy 343.512648 -410.948886)
			)
		)
	)
	(zone
		(layer "F.Cu")
		(hatch none 0.5)
		(connect_pads
			(clearance 0)
		)
		(min_thickness 0.25)
		(keepout
			(tracks allowed)
			(vias allowed)
			(pads allowed)
			(copperpour allowed)
			(footprints allowed)
		)
		(placement
			(enabled no)
			(sheetname "")
		)
		(fill
			(thermal_gap 0.5)
			(thermal_bridge_width 0.5)
			(island_removal_mode 0)
		)
		(polygon
			(pts
				(xy 311.94248 -201.366628) (xy 311.94248 -200.92289) (xy 314.15228 -200.92289) (xy 314.15228 -201.366628)
			)
		)
	)
	(zone
		(layer "F.Cu")
		(hatch none 0.5)
		(connect_pads
			(clearance 0)
		)
		(min_thickness 0.25)
		(keepout
			(tracks allowed)
			(vias allowed)
			(pads allowed)
			(copperpour allowed)
			(footprints allowed)
		)
		(placement
			(enabled no)
			(sheetname "")
		)
		(fill
			(thermal_gap 0.5)
			(thermal_bridge_width 0.5)
			(island_removal_mode 0)
		)
		(polygon
			(pts
				(xy 386.31114 -282.501848) (xy 386.59816 -282.501848) (xy 386.62864 -282.471368) (xy 386.62864 -281.843988)
				(xy 386.54228 -281.757628) (xy 386.35432 -281.757628) (xy 386.28066 -281.831288) (xy 386.28066 -282.471368)
			)
		)
	)
	(zone
		(layer "F.Cu")
		(hatch none 0.5)
		(connect_pads
			(clearance 0)
		)
		(min_thickness 0.25)
		(keepout
			(tracks allowed)
			(vias allowed)
			(pads allowed)
			(copperpour allowed)
			(footprints allowed)
		)
		(placement
			(enabled no)
			(sheetname "")
		)
		(fill
			(thermal_gap 0.5)
			(thermal_bridge_width 0.5)
			(island_removal_mode 0)
		)
		(polygon
			(pts
				(xy 292.67531 -308.46649) (xy 292.67531 -308.022752) (xy 295.000426 -308.022752) (xy 295.000426 -308.46649)
			)
		)
	)
	(zone
		(layer "F.Cu")
		(hatch none 0.5)
		(connect_pads
			(clearance 0)
		)
		(min_thickness 0.25)
		(keepout
			(tracks allowed)
			(vias allowed)
			(pads allowed)
			(copperpour allowed)
			(footprints not_allowed)
		)
		(placement
			(enabled no)
			(sheetname "")
		)
		(fill
			(thermal_gap 0.5)
			(thermal_bridge_width 0.5)
			(island_removal_mode 0)
		)
		(polygon
			(pts
				(arc
					(start 459.799944 -22.29993)
					(mid 464.799934 -17.29994)
					(end 469.799924 -22.29993)
				)
				(arc
					(start 469.799924 -22.29993)
					(mid 464.799934 -27.29992)
					(end 459.799944 -22.29993)
				)
			)
		)
	)
	(zone
		(layer "F.Cu")
		(hatch none 0.5)
		(connect_pads
			(clearance 0)
		)
		(min_thickness 0.25)
		(keepout
			(tracks allowed)
			(vias allowed)
			(pads allowed)
			(copperpour allowed)
			(footprints allowed)
		)
		(placement
			(enabled no)
			(sheetname "")
		)
		(fill
			(thermal_gap 0.5)
			(thermal_bridge_width 0.5)
			(island_removal_mode 0)
		)
		(polygon
			(pts
				(xy 165.335458 -314.304934) (xy 165.335458 -314.076334) (xy 167.367458 -314.076334) (xy 167.367458 -314.304934)
			)
		)
	)
	(zone
		(layer "F.Cu")
		(hatch none 0.5)
		(connect_pads
			(clearance 0)
		)
		(min_thickness 0.25)
		(keepout
			(tracks allowed)
			(vias allowed)
			(pads allowed)
			(copperpour allowed)
			(footprints allowed)
		)
		(placement
			(enabled no)
			(sheetname "")
		)
		(fill
			(thermal_gap 0.5)
			(thermal_bridge_width 0.5)
			(island_removal_mode 0)
		)
		(polygon
			(pts
				(xy 134.57936 -289.047428) (xy 134.86638 -289.047428) (xy 134.89686 -289.016948) (xy 134.89686 -288.389568)
				(xy 134.8105 -288.303208) (xy 134.62254 -288.303208) (xy 134.54888 -288.376868) (xy 134.54888 -289.016948)
			)
		)
	)
	(zone
		(layer "F.Cu")
		(hatch none 0.5)
		(connect_pads
			(clearance 0)
		)
		(min_thickness 0.25)
		(keepout
			(tracks allowed)
			(vias allowed)
			(pads allowed)
			(copperpour allowed)
			(footprints allowed)
		)
		(placement
			(enabled no)
			(sheetname "")
		)
		(fill
			(thermal_gap 0.5)
			(thermal_bridge_width 0.5)
			(island_removal_mode 0)
		)
		(polygon
			(pts
				(xy 56.484012 -245.566438) (xy 56.484012 -245.1227) (xy 58.617612 -245.1227) (xy 58.617612 -245.566438)
			)
		)
	)
	(zone
		(layer "F.Cu")
		(hatch none 0.5)
		(connect_pads
			(clearance 0)
		)
		(min_thickness 0.25)
		(keepout
			(tracks allowed)
			(vias allowed)
			(pads allowed)
			(copperpour allowed)
			(footprints allowed)
		)
		(placement
			(enabled no)
			(sheetname "")
		)
		(fill
			(thermal_gap 0.5)
			(thermal_bridge_width 0.5)
			(island_removal_mode 0)
		)
		(polygon
			(pts
				(xy 428.363126 -252.25502) (xy 428.363126 -252.02642) (xy 430.395126 -252.02642) (xy 430.395126 -252.25502)
			)
		)
	)
	(zone
		(layer "F.Cu")
		(hatch none 0.5)
		(connect_pads
			(clearance 0)
		)
		(min_thickness 0.25)
		(keepout
			(tracks allowed)
			(vias allowed)
			(pads allowed)
			(copperpour allowed)
			(footprints allowed)
		)
		(placement
			(enabled no)
			(sheetname "")
		)
		(fill
			(thermal_gap 0.5)
			(thermal_bridge_width 0.5)
			(island_removal_mode 0)
		)
		(polygon
			(pts
				(xy 458.538326 -264.15492) (xy 458.538326 -263.92632) (xy 460.570326 -263.92632) (xy 460.570326 -264.15492)
			)
		)
	)
	(zone
		(layer "F.Cu")
		(hatch none 0.5)
		(connect_pads
			(clearance 0)
		)
		(min_thickness 0.25)
		(keepout
			(tracks allowed)
			(vias allowed)
			(pads allowed)
			(copperpour allowed)
			(footprints not_allowed)
		)
		(placement
			(enabled no)
			(sheetname "")
		)
		(fill
			(thermal_gap 0.5)
			(thermal_bridge_width 0.5)
			(island_removal_mode 0)
		)
		(polygon
			(pts
				(xy 377.299982 -440.889898)
				(arc
					(start 377.299982 -430.310036)
					(mid 371.300707 -427.600106)
					(end 365.300006 -430.306988)
				)
				(xy 365.300006 -440.892946) (xy 365.386874 -440.989974) (xy 377.21032 -440.989974)
			)
		)
	)
	(zone
		(layer "F.Cu")
		(hatch none 0.5)
		(connect_pads
			(clearance 0)
		)
		(min_thickness 0.25)
		(keepout
			(tracks allowed)
			(vias allowed)
			(pads allowed)
			(copperpour allowed)
			(footprints allowed)
		)
		(placement
			(enabled no)
			(sheetname "")
		)
		(fill
			(thermal_gap 0.5)
			(thermal_bridge_width 0.5)
			(island_removal_mode 0)
		)
		(polygon
			(pts
				(xy 180.423058 -218.254834) (xy 180.423058 -218.026234) (xy 182.455058 -218.026234) (xy 182.455058 -218.254834)
			)
		)
	)
	(zone
		(layer "F.Cu")
		(hatch none 0.5)
		(connect_pads
			(clearance 0)
		)
		(min_thickness 0.25)
		(keepout
			(tracks allowed)
			(vias allowed)
			(pads allowed)
			(copperpour allowed)
			(footprints allowed)
		)
		(placement
			(enabled no)
			(sheetname "")
		)
		(fill
			(thermal_gap 0.5)
			(thermal_bridge_width 0.5)
			(island_removal_mode 0)
		)
		(polygon
			(pts
				(xy 114.068098 -415.08172) (xy 110.532418 -415.08172) (xy 110.532418 -412.99892) (xy 114.068098 -412.99892)
			)
		)
	)
	(zone
		(layer "F.Cu")
		(hatch none 0.5)
		(connect_pads
			(clearance 0)
		)
		(min_thickness 0.25)
		(keepout
			(tracks allowed)
			(vias allowed)
			(pads allowed)
			(copperpour allowed)
			(footprints allowed)
		)
		(placement
			(enabled no)
			(sheetname "")
		)
		(fill
			(thermal_gap 0.5)
			(thermal_bridge_width 0.5)
			(island_removal_mode 0)
		)
		(polygon
			(pts
				(xy 289.231578 -202.216512) (xy 289.231578 -201.772774) (xy 291.556694 -201.772774) (xy 291.556694 -202.216512)
			)
		)
	)
	(zone
		(layer "F.Cu")
		(hatch none 0.5)
		(connect_pads
			(clearance 0)
		)
		(min_thickness 0.25)
		(keepout
			(tracks allowed)
			(vias allowed)
			(pads allowed)
			(copperpour allowed)
			(footprints allowed)
		)
		(placement
			(enabled no)
			(sheetname "")
		)
		(fill
			(thermal_gap 0.5)
			(thermal_bridge_width 0.5)
			(island_removal_mode 0)
		)
		(polygon
			(pts
				(xy 289.231578 -213.266782) (xy 289.231578 -212.823044) (xy 291.556694 -212.823044) (xy 291.556694 -213.266782)
			)
		)
	)
	(zone
		(layer "F.Cu")
		(hatch none 0.5)
		(connect_pads
			(clearance 0)
		)
		(min_thickness 0.25)
		(keepout
			(tracks allowed)
			(vias allowed)
			(pads allowed)
			(copperpour allowed)
			(footprints allowed)
		)
		(placement
			(enabled no)
			(sheetname "")
		)
		(fill
			(thermal_gap 0.5)
			(thermal_bridge_width 0.5)
			(island_removal_mode 0)
		)
		(polygon
			(pts
				(xy 161.891726 -251.404882) (xy 161.891726 -251.176282) (xy 163.923726 -251.176282) (xy 163.923726 -251.404882)
			)
		)
	)
	(zone
		(layer "F.Cu")
		(hatch none 0.5)
		(connect_pads
			(clearance 0)
		)
		(min_thickness 0.25)
		(keepout
			(tracks not_allowed)
			(vias allowed)
			(pads allowed)
			(copperpour not_allowed)
			(footprints allowed)
		)
		(placement
			(enabled no)
			(sheetname "")
		)
		(fill
			(thermal_gap 0.5)
			(thermal_bridge_width 0.5)
			(island_removal_mode 0)
		)
		(polygon
			(pts
				(xy 439.968894 -11.992356) (xy 440.144154 -11.992356) (xy 440.172094 -11.964416) (xy 440.172094 -10.569956)
				(xy 440.149234 -10.547096) (xy 439.979054 -10.547096) (xy 439.958734 -10.567416) (xy 439.958734 -11.982196)
			)
		)
	)
	(zone
		(layer "F.Cu")
		(hatch none 0.5)
		(connect_pads
			(clearance 0)
		)
		(min_thickness 0.25)
		(keepout
			(tracks allowed)
			(vias allowed)
			(pads allowed)
			(copperpour allowed)
			(footprints allowed)
		)
		(placement
			(enabled no)
			(sheetname "")
		)
		(fill
			(thermal_gap 0.5)
			(thermal_bridge_width 0.5)
			(island_removal_mode 0)
		)
		(polygon
			(pts
				(xy 56.37911 -205.616556) (xy 56.37911 -205.172818) (xy 58.704226 -205.172818) (xy 58.704226 -205.616556)
			)
		)
	)
	(zone
		(layer "F.Cu")
		(hatch none 0.5)
		(connect_pads
			(clearance 0)
		)
		(min_thickness 0.25)
		(keepout
			(tracks allowed)
			(vias allowed)
			(pads allowed)
			(copperpour allowed)
			(footprints allowed)
		)
		(placement
			(enabled no)
			(sheetname "")
		)
		(fill
			(thermal_gap 0.5)
			(thermal_bridge_width 0.5)
			(island_removal_mode 0)
		)
		(polygon
			(pts
				(xy 165.335458 -292.204902) (xy 165.335458 -291.976302) (xy 167.367458 -291.976302) (xy 167.367458 -292.204902)
			)
		)
	)
	(zone
		(layer "F.Cu")
		(hatch none 0.5)
		(connect_pads
			(clearance 0)
		)
		(min_thickness 0.25)
		(keepout
			(tracks allowed)
			(vias allowed)
			(pads allowed)
			(copperpour allowed)
			(footprints allowed)
		)
		(placement
			(enabled no)
			(sheetname "")
		)
		(fill
			(thermal_gap 0.5)
			(thermal_bridge_width 0.5)
			(island_removal_mode 0)
		)
		(polygon
			(pts
				(xy 368.534442 -332.908402) (xy 366.718342 -332.908402) (xy 366.718342 -331.529182) (xy 368.534442 -331.529182)
			)
		)
	)
	(zone
		(layer "F.Cu")
		(hatch none 0.5)
		(connect_pads
			(clearance 0)
		)
		(min_thickness 0.25)
		(keepout
			(tracks allowed)
			(vias allowed)
			(pads allowed)
			(copperpour allowed)
			(footprints allowed)
		)
		(placement
			(enabled no)
			(sheetname "")
		)
		(fill
			(thermal_gap 0.5)
			(thermal_bridge_width 0.5)
			(island_removal_mode 0)
		)
		(polygon
			(pts
				(xy 44.735242 -239.616488) (xy 44.735242 -239.17275) (xy 47.060358 -239.17275) (xy 47.060358 -239.616488)
			)
		)
	)
	(zone
		(layer "F.Cu")
		(hatch none 0.5)
		(connect_pads
			(clearance 0)
		)
		(min_thickness 0.25)
		(keepout
			(tracks allowed)
			(vias allowed)
			(pads allowed)
			(copperpour allowed)
			(footprints allowed)
		)
		(placement
			(enabled no)
			(sheetname "")
		)
		(fill
			(thermal_gap 0.5)
			(thermal_bridge_width 0.5)
			(island_removal_mode 0)
		)
		(polygon
			(pts
				(xy 409.831794 -223.976438) (xy 411.863794 -223.976438) (xy 411.863794 -224.205038) (xy 409.831794 -224.205038)
				(xy 409.69565 -224.205038) (xy 409.64866 -224.205038) (xy 409.64866 -223.976438) (xy 409.69565 -223.976438)
			)
		)
	)
	(zone
		(layer "F.Cu")
		(hatch none 0.5)
		(connect_pads
			(clearance 0)
		)
		(min_thickness 0.25)
		(keepout
			(tracks allowed)
			(vias allowed)
			(pads allowed)
			(copperpour allowed)
			(footprints allowed)
		)
		(placement
			(enabled no)
			(sheetname "")
		)
		(fill
			(thermal_gap 0.5)
			(thermal_bridge_width 0.5)
			(island_removal_mode 0)
		)
		(polygon
			(pts
				(xy 76.34224 -350.845628) (xy 76.34224 -349.504508) (xy 77.61224 -349.504508) (xy 77.61224 -350.845628)
			)
		)
	)
	(zone
		(layer "F.Cu")
		(hatch none 0.5)
		(connect_pads
			(clearance 0)
		)
		(min_thickness 0.25)
		(keepout
			(tracks allowed)
			(vias allowed)
			(pads allowed)
			(copperpour allowed)
			(footprints allowed)
		)
		(placement
			(enabled no)
			(sheetname "")
		)
		(fill
			(thermal_gap 0.5)
			(thermal_bridge_width 0.5)
			(island_removal_mode 0)
		)
		(polygon
			(pts
				(xy 51.370992 -174.994824) (xy 52.702968 -174.994824) (xy 52.90185 -175.193706) (xy 52.90185 -176.985676)
				(xy 52.098702 -177.788824) (xy 49.620678 -177.788824) (xy 48.261016 -176.429162) (xy 48.261016 -170.937428)
				(xy 49.400714 -169.79773) (xy 53.321204 -169.79773) (xy 53.952648 -170.429174) (xy 53.952648 -172.145198)
				(xy 53.396134 -172.701712) (xy 51.247548 -172.701712) (xy 51.178968 -172.770292) (xy 51.178968 -174.8028)
			)
		)
	)
	(zone
		(layer "F.Cu")
		(hatch none 0.5)
		(connect_pads
			(clearance 0)
		)
		(min_thickness 0.25)
		(keepout
			(tracks allowed)
			(vias allowed)
			(pads allowed)
			(copperpour allowed)
			(footprints allowed)
		)
		(placement
			(enabled no)
			(sheetname "")
		)
		(fill
			(thermal_gap 0.5)
			(thermal_bridge_width 0.5)
			(island_removal_mode 0)
		)
		(polygon
			(pts
				(xy 54.995572 -410.948886) (xy 54.995572 -406.105868) (xy 56.879998 -406.105868) (xy 56.879998 -410.948886)
			)
		)
	)
	(zone
		(layer "F.Cu")
		(hatch none 0.5)
		(connect_pads
			(clearance 0)
		)
		(min_thickness 0.25)
		(keepout
			(tracks allowed)
			(vias allowed)
			(pads allowed)
			(copperpour allowed)
			(footprints allowed)
		)
		(placement
			(enabled no)
			(sheetname "")
		)
		(fill
			(thermal_gap 0.5)
			(thermal_bridge_width 0.5)
			(island_removal_mode 0)
		)
		(polygon
			(pts
				(xy 387.232144 -235.200952) (xy 387.43509 -234.998006) (xy 387.43509 -234.95508) (xy 386.991606 -234.511342)
				(xy 386.869432 -234.511342) (xy 386.736336 -234.644184) (xy 386.736336 -234.748324) (xy 387.188964 -235.200952)
			)
		)
	)
	(zone
		(layer "F.Cu")
		(hatch none 0.5)
		(connect_pads
			(clearance 0)
		)
		(min_thickness 0.25)
		(keepout
			(tracks allowed)
			(vias allowed)
			(pads allowed)
			(copperpour allowed)
			(footprints allowed)
		)
		(placement
			(enabled no)
			(sheetname "")
		)
		(fill
			(thermal_gap 0.5)
			(thermal_bridge_width 0.5)
			(island_removal_mode 0)
		)
		(polygon
			(pts
				(xy 405.731726 -274.354798) (xy 405.731726 -274.126198) (xy 407.763726 -274.126198) (xy 407.763726 -274.354798)
			)
		)
	)
	(zone
		(layer "F.Cu")
		(hatch none 0.5)
		(connect_pads
			(clearance 0)
		)
		(min_thickness 0.25)
		(keepout
			(tracks allowed)
			(vias allowed)
			(pads allowed)
			(copperpour allowed)
			(footprints allowed)
		)
		(placement
			(enabled no)
			(sheetname "")
		)
		(fill
			(thermal_gap 0.5)
			(thermal_bridge_width 0.5)
			(island_removal_mode 0)
		)
		(polygon
			(pts
				(xy 428.363126 -208.90484) (xy 428.363126 -208.67624) (xy 430.395126 -208.67624) (xy 430.395126 -208.90484)
			)
		)
	)
	(zone
		(layer "F.Cu")
		(hatch none 0.5)
		(connect_pads
			(clearance 0)
		)
		(min_thickness 0.25)
		(keepout
			(tracks allowed)
			(vias allowed)
			(pads allowed)
			(copperpour allowed)
			(footprints allowed)
		)
		(placement
			(enabled no)
			(sheetname "")
		)
		(fill
			(thermal_gap 0.5)
			(thermal_bridge_width 0.5)
			(island_removal_mode 0)
		)
		(polygon
			(pts
				(xy 14.560042 -296.56659) (xy 14.560042 -296.122852) (xy 16.885158 -296.122852) (xy 16.885158 -296.56659)
			)
		)
	)
	(zone
		(layer "F.Cu")
		(hatch none 0.5)
		(connect_pads
			(clearance 0)
		)
		(min_thickness 0.25)
		(keepout
			(tracks allowed)
			(vias allowed)
			(pads allowed)
			(copperpour allowed)
			(footprints allowed)
		)
		(placement
			(enabled no)
			(sheetname "")
		)
		(fill
			(thermal_gap 0.5)
			(thermal_bridge_width 0.5)
			(island_removal_mode 0)
		)
		(polygon
			(pts
				(xy 210.598258 -225.904806) (xy 210.598258 -225.676206) (xy 212.630258 -225.676206) (xy 212.630258 -225.904806)
			)
		)
	)
	(zone
		(layer "F.Cu")
		(hatch none 0.5)
		(connect_pads
			(clearance 0)
		)
		(min_thickness 0.25)
		(keepout
			(tracks allowed)
			(vias allowed)
			(pads allowed)
			(copperpour allowed)
			(footprints allowed)
		)
		(placement
			(enabled no)
			(sheetname "")
		)
		(fill
			(thermal_gap 0.5)
			(thermal_bridge_width 0.5)
			(island_removal_mode 0)
		)
		(polygon
			(pts
				(xy 63.977012 -267.66647) (xy 63.977012 -267.222732) (xy 66.161412 -267.222732) (xy 66.161412 -267.66647)
			)
		)
	)
	(zone
		(layer "F.Cu")
		(hatch none 0.5)
		(connect_pads
			(clearance 0)
		)
		(min_thickness 0.25)
		(keepout
			(tracks allowed)
			(vias allowed)
			(pads allowed)
			(copperpour allowed)
			(footprints allowed)
		)
		(placement
			(enabled no)
			(sheetname "")
		)
		(fill
			(thermal_gap 0.5)
			(thermal_bridge_width 0.5)
			(island_removal_mode 0)
		)
		(polygon
			(pts
				(xy 158.76016 -46.1264) (xy 158.76016 -45.11548) (xy 160.42894 -45.11548) (xy 160.42894 -46.1264)
			)
		)
	)
	(zone
		(layer "F.Cu")
		(hatch none 0.5)
		(connect_pads
			(clearance 0)
		)
		(min_thickness 0.25)
		(keepout
			(tracks allowed)
			(vias allowed)
			(pads allowed)
			(copperpour allowed)
			(footprints allowed)
		)
		(placement
			(enabled no)
			(sheetname "")
		)
		(fill
			(thermal_gap 0.5)
			(thermal_bridge_width 0.5)
			(island_removal_mode 0)
		)
		(polygon
			(pts
				(xy 165.335458 -282.005024) (xy 165.335458 -281.776424) (xy 167.367458 -281.776424) (xy 167.367458 -282.005024)
			)
		)
	)
	(zone
		(layer "F.Cu")
		(hatch none 0.5)
		(connect_pads
			(clearance 0)
		)
		(min_thickness 0.25)
		(keepout
			(tracks allowed)
			(vias allowed)
			(pads allowed)
			(copperpour allowed)
			(footprints allowed)
		)
		(placement
			(enabled no)
			(sheetname "")
		)
		(fill
			(thermal_gap 0.5)
			(thermal_bridge_width 0.5)
			(island_removal_mode 0)
		)
		(polygon
			(pts
				(xy 51.719734 -20.10791) (xy 51.719734 -16.973296) (xy 53.498496 -16.973296) (xy 53.498496 -20.10791)
			)
		)
	)
	(zone
		(layer "F.Cu")
		(hatch none 0.5)
		(connect_pads
			(clearance 0)
		)
		(min_thickness 0.25)
		(keepout
			(tracks allowed)
			(vias allowed)
			(pads allowed)
			(copperpour allowed)
			(footprints allowed)
		)
		(placement
			(enabled no)
			(sheetname "")
		)
		(fill
			(thermal_gap 0.5)
			(thermal_bridge_width 0.5)
			(island_removal_mode 0)
		)
		(polygon
			(pts
				(xy 56.37911 -272.322798) (xy 58.704226 -272.322798) (xy 58.971688 -272.322798) (xy 58.971688 -273.26463)
				(xy 56.044338 -273.26463) (xy 56.044338 -272.322798)
			)
		)
	)
	(zone
		(layer "F.Cu")
		(hatch none 0.5)
		(connect_pads
			(clearance 0)
		)
		(min_thickness 0.25)
		(keepout
			(tracks allowed)
			(vias allowed)
			(pads allowed)
			(copperpour allowed)
			(footprints allowed)
		)
		(placement
			(enabled no)
			(sheetname "")
		)
		(fill
			(thermal_gap 0.5)
			(thermal_bridge_width 0.5)
			(island_removal_mode 0)
		)
		(polygon
			(pts
				(xy 176.721262 -319.243202) (xy 176.721262 -316.881002) (xy 179.337462 -316.881002) (xy 179.337462 -319.243202)
			)
		)
	)
	(zone
		(layer "F.Cu")
		(hatch none 0.5)
		(connect_pads
			(clearance 0)
		)
		(min_thickness 0.25)
		(keepout
			(tracks allowed)
			(vias allowed)
			(pads allowed)
			(copperpour allowed)
			(footprints allowed)
		)
		(placement
			(enabled no)
			(sheetname "")
		)
		(fill
			(thermal_gap 0.5)
			(thermal_bridge_width 0.5)
			(island_removal_mode 0)
		)
		(polygon
			(pts
				(xy 126.19482 -360.733848) (xy 126.19482 -359.900728) (xy 126.8603 -359.900728) (xy 126.8603 -360.733848)
			)
		)
	)
	(zone
		(layer "F.Cu")
		(hatch none 0.5)
		(connect_pads
			(clearance 0)
		)
		(min_thickness 0.25)
		(keepout
			(tracks allowed)
			(vias allowed)
			(pads allowed)
			(copperpour allowed)
			(footprints allowed)
		)
		(placement
			(enabled no)
			(sheetname "")
		)
		(fill
			(thermal_gap 0.5)
			(thermal_bridge_width 0.5)
			(island_removal_mode 0)
		)
		(polygon
			(pts
				(xy 277.58771 -203.06665) (xy 277.58771 -202.622912) (xy 279.912826 -202.622912) (xy 279.912826 -203.06665)
			)
		)
	)
	(zone
		(layer "F.Cu")
		(hatch none 0.5)
		(connect_pads
			(clearance 0)
		)
		(min_thickness 0.25)
		(keepout
			(tracks allowed)
			(vias allowed)
			(pads allowed)
			(copperpour allowed)
			(footprints allowed)
		)
		(placement
			(enabled no)
			(sheetname "")
		)
		(fill
			(thermal_gap 0.5)
			(thermal_bridge_width 0.5)
			(island_removal_mode 0)
		)
		(polygon
			(pts
				(xy 210.598258 -205.504796) (xy 210.598258 -205.276196) (xy 212.630258 -205.276196) (xy 212.630258 -205.504796)
			)
		)
	)
	(zone
		(layer "F.Cu")
		(hatch none 0.5)
		(connect_pads
			(clearance 0)
		)
		(min_thickness 0.25)
		(keepout
			(tracks allowed)
			(vias allowed)
			(pads allowed)
			(copperpour allowed)
			(footprints allowed)
		)
		(placement
			(enabled no)
			(sheetname "")
		)
		(fill
			(thermal_gap 0.5)
			(thermal_bridge_width 0.5)
			(island_removal_mode 0)
		)
		(polygon
			(pts
				(xy 14.560296 -274.466812) (xy 14.560296 -274.023074) (xy 16.885412 -274.023074) (xy 16.885412 -274.466812)
			)
		)
	)
	(zone
		(layer "F.Cu")
		(hatch none 0.5)
		(connect_pads
			(clearance 0)
		)
		(min_thickness 0.25)
		(keepout
			(tracks allowed)
			(vias allowed)
			(pads allowed)
			(copperpour allowed)
			(footprints allowed)
		)
		(placement
			(enabled no)
			(sheetname "")
		)
		(fill
			(thermal_gap 0.5)
			(thermal_bridge_width 0.5)
			(island_removal_mode 0)
		)
		(polygon
			(pts
				(xy 161.633662 -319.243202) (xy 161.633662 -318.252602) (xy 161.176462 -317.795402) (xy 161.176462 -317.084202)
				(xy 161.379662 -316.881002) (xy 161.633662 -316.881002) (xy 164.249862 -316.881002) (xy 164.249862 -319.243202)
			)
		)
	)
	(zone
		(layer "F.Cu")
		(hatch none 0.5)
		(connect_pads
			(clearance 0)
		)
		(min_thickness 0.25)
		(keepout
			(tracks allowed)
			(vias allowed)
			(pads allowed)
			(copperpour allowed)
			(footprints allowed)
		)
		(placement
			(enabled no)
			(sheetname "")
		)
		(fill
			(thermal_gap 0.5)
			(thermal_bridge_width 0.5)
			(island_removal_mode 0)
		)
		(polygon
			(pts
				(xy 333.58074 -217.686128) (xy 333.86776 -217.686128) (xy 333.89824 -217.655648) (xy 333.89824 -217.028268)
				(xy 333.81188 -216.941908) (xy 333.62392 -216.941908) (xy 333.55026 -217.015568) (xy 333.55026 -217.655648)
			)
		)
	)
	(zone
		(layer "F.Cu")
		(hatch none 0.5)
		(connect_pads
			(clearance 0)
		)
		(min_thickness 0.25)
		(keepout
			(tracks allowed)
			(vias allowed)
			(pads allowed)
			(copperpour allowed)
			(footprints allowed)
		)
		(placement
			(enabled no)
			(sheetname "")
		)
		(fill
			(thermal_gap 0.5)
			(thermal_bridge_width 0.5)
			(island_removal_mode 0)
		)
		(polygon
			(pts
				(xy 192.066926 -245.454932) (xy 192.066926 -245.226332) (xy 194.098926 -245.226332) (xy 194.098926 -245.454932)
			)
		)
	)
	(zone
		(layer "F.Cu")
		(hatch none 0.5)
		(connect_pads
			(clearance 0)
		)
		(min_thickness 0.25)
		(keepout
			(tracks allowed)
			(vias allowed)
			(pads allowed)
			(copperpour allowed)
			(footprints allowed)
		)
		(placement
			(enabled no)
			(sheetname "")
		)
		(fill
			(thermal_gap 0.5)
			(thermal_bridge_width 0.5)
			(island_removal_mode 0)
		)
		(polygon
			(pts
				(xy 307.76291 -283.816552) (xy 307.76291 -283.372814) (xy 310.088026 -283.372814) (xy 310.088026 -283.816552)
			)
		)
	)
	(zone
		(layer "F.Cu")
		(hatch none 0.5)
		(connect_pads
			(clearance 0)
		)
		(min_thickness 0.25)
		(keepout
			(tracks allowed)
			(vias allowed)
			(pads allowed)
			(copperpour allowed)
			(footprints not_allowed)
		)
		(placement
			(enabled no)
			(sheetname "")
		)
		(fill
			(thermal_gap 0.5)
			(thermal_bridge_width 0.5)
			(island_removal_mode 0)
		)
		(polygon
			(pts
				(xy 350.164908 -296.720006) (xy 369.57508 -296.720006) (xy 369.57508 -293.269924) (xy 350.164908 -293.269924)
			)
		)
	)
	(zone
		(layer "F.Cu")
		(hatch none 0.5)
		(connect_pads
			(clearance 0)
		)
		(min_thickness 0.25)
		(keepout
			(tracks allowed)
			(vias allowed)
			(pads allowed)
			(copperpour allowed)
			(footprints not_allowed)
		)
		(placement
			(enabled no)
			(sheetname "")
		)
		(fill
			(thermal_gap 0.5)
			(thermal_bridge_width 0.5)
			(island_removal_mode 0)
		)
		(polygon
			(pts
				(arc
					(start 14.750034 -36.999926)
					(mid 6.531776 -39.451616)
					(end 0.999998 -46.005242)
				)
				(arc
					(start 0.999998 -57.994804)
					(mid 6.531771 -64.548438)
					(end 14.750034 -67.00012)
				)
				(xy 14.750034 -66.324988) (xy 11.75004 -66.324988) (xy 11.75004 -37.675058) (xy 14.750034 -37.675058)
			)
		)
	)
	(zone
		(layer "F.Cu")
		(hatch none 0.5)
		(connect_pads
			(clearance 0)
		)
		(min_thickness 0.25)
		(keepout
			(tracks allowed)
			(vias allowed)
			(pads allowed)
			(copperpour allowed)
			(footprints allowed)
		)
		(placement
			(enabled no)
			(sheetname "")
		)
		(fill
			(thermal_gap 0.5)
			(thermal_bridge_width 0.5)
			(island_removal_mode 0)
		)
		(polygon
			(pts
				(xy 277.58771 -305.916584) (xy 277.58771 -305.472846) (xy 279.912826 -305.472846) (xy 279.912826 -305.916584)
			)
		)
	)
	(zone
		(layer "F.Cu")
		(hatch none 0.5)
		(connect_pads
			(clearance 0)
		)
		(min_thickness 0.25)
		(keepout
			(tracks allowed)
			(vias allowed)
			(pads allowed)
			(copperpour allowed)
			(footprints allowed)
		)
		(placement
			(enabled no)
			(sheetname "")
		)
		(fill
			(thermal_gap 0.5)
			(thermal_bridge_width 0.5)
			(island_removal_mode 0)
		)
		(polygon
			(pts
				(xy 413.275526 -311.755028) (xy 413.275526 -311.526428) (xy 415.307526 -311.526428) (xy 415.307526 -311.755028)
			)
		)
	)
	(zone
		(layer "F.Cu")
		(hatch none 0.5)
		(connect_pads
			(clearance 0)
		)
		(min_thickness 0.25)
		(keepout
			(tracks allowed)
			(vias allowed)
			(pads allowed)
			(copperpour allowed)
			(footprints allowed)
		)
		(placement
			(enabled no)
			(sheetname "")
		)
		(fill
			(thermal_gap 0.5)
			(thermal_bridge_width 0.5)
			(island_removal_mode 0)
		)
		(polygon
			(pts
				(xy 161.891726 -214.85479) (xy 161.891726 -214.62619) (xy 163.923726 -214.62619) (xy 163.923726 -214.85479)
			)
		)
	)
	(zone
		(layer "F.Cu")
		(hatch none 0.5)
		(connect_pads
			(clearance 0)
		)
		(min_thickness 0.25)
		(keepout
			(tracks allowed)
			(vias allowed)
			(pads allowed)
			(copperpour allowed)
			(footprints allowed)
		)
		(placement
			(enabled no)
			(sheetname "")
		)
		(fill
			(thermal_gap 0.5)
			(thermal_bridge_width 0.5)
			(island_removal_mode 0)
		)
		(polygon
			(pts
				(xy 89.88298 -215.262968) (xy 90.17 -215.262968) (xy 90.20048 -215.232488) (xy 90.20048 -214.605108)
				(xy 90.11412 -214.518748) (xy 89.92616 -214.518748) (xy 89.8525 -214.592408) (xy 89.8525 -215.232488)
			)
		)
	)
	(zone
		(layer "F.Cu")
		(hatch none 0.5)
		(connect_pads
			(clearance 0)
		)
		(min_thickness 0.25)
		(keepout
			(tracks allowed)
			(vias allowed)
			(pads allowed)
			(copperpour allowed)
			(footprints allowed)
		)
		(placement
			(enabled no)
			(sheetname "")
		)
		(fill
			(thermal_gap 0.5)
			(thermal_bridge_width 0.5)
			(island_removal_mode 0)
		)
		(polygon
			(pts
				(xy 210.598258 -207.204818) (xy 210.598258 -206.976218) (xy 212.630258 -206.976218) (xy 212.630258 -207.204818)
			)
		)
	)
	(zone
		(layer "F.Cu")
		(hatch none 0.5)
		(connect_pads
			(clearance 0)
		)
		(min_thickness 0.25)
		(keepout
			(tracks allowed)
			(vias allowed)
			(pads allowed)
			(copperpour allowed)
			(footprints not_allowed)
		)
		(placement
			(enabled no)
			(sheetname "")
		)
		(fill
			(thermal_gap 0.5)
			(thermal_bridge_width 0.5)
			(island_removal_mode 0)
		)
		(polygon
			(pts
				(arc
					(start 174.749968 -435.600094)
					(mid 179.749958 -430.600104)
					(end 184.749948 -435.600094)
				)
				(arc
					(start 184.749948 -435.600094)
					(mid 179.749958 -440.600084)
					(end 174.749968 -435.600094)
				)
			)
		)
	)
	(zone
		(layer "F.Cu")
		(hatch none 0.5)
		(connect_pads
			(clearance 0)
		)
		(min_thickness 0.25)
		(keepout
			(tracks allowed)
			(vias allowed)
			(pads allowed)
			(copperpour allowed)
			(footprints not_allowed)
		)
		(placement
			(enabled no)
			(sheetname "")
		)
		(fill
			(thermal_gap 0.5)
			(thermal_bridge_width 0.5)
			(island_removal_mode 0)
		)
		(polygon
			(pts
				(arc
					(start 375.899934 -22.29993)
					(mid 380.899924 -17.29994)
					(end 385.899914 -22.29993)
				)
				(arc
					(start 385.899914 -22.29993)
					(mid 380.899924 -27.29992)
					(end 375.899934 -22.29993)
				)
			)
		)
	)
	(zone
		(layer "F.Cu")
		(hatch none 0.5)
		(connect_pads
			(clearance 0)
		)
		(min_thickness 0.25)
		(keepout
			(tracks allowed)
			(vias allowed)
			(pads allowed)
			(copperpour allowed)
			(footprints allowed)
		)
		(placement
			(enabled no)
			(sheetname "")
		)
		(fill
			(thermal_gap 0.5)
			(thermal_bridge_width 0.5)
			(island_removal_mode 0)
		)
		(polygon
			(pts
				(xy 446.09766 -75.288648) (xy 446.09766 -70.673468) (xy 450.26961 -70.673468) (xy 450.26961 -75.288648)
			)
		)
	)
	(zone
		(layer "F.Cu")
		(hatch none 0.5)
		(connect_pads
			(clearance 0)
		)
		(min_thickness 0.25)
		(keepout
			(tracks allowed)
			(vias allowed)
			(pads allowed)
			(copperpour allowed)
			(footprints allowed)
		)
		(placement
			(enabled no)
			(sheetname "")
		)
		(fill
			(thermal_gap 0.5)
			(thermal_bridge_width 0.5)
			(island_removal_mode 0)
		)
		(polygon
			(pts
				(xy 73.375012 -410.948886) (xy 73.375012 -406.105868) (xy 75.259438 -406.105868) (xy 75.259438 -410.948886)
			)
		)
	)
	(zone
		(layer "F.Cu")
		(hatch none 0.5)
		(connect_pads
			(clearance 0)
		)
		(min_thickness 0.25)
		(keepout
			(tracks allowed)
			(vias allowed)
			(pads allowed)
			(copperpour allowed)
			(footprints allowed)
		)
		(placement
			(enabled no)
			(sheetname "")
		)
		(fill
			(thermal_gap 0.5)
			(thermal_bridge_width 0.5)
			(island_removal_mode 0)
		)
		(polygon
			(pts
				(xy 55.0291 -167.752268) (xy 55.0291 -164.216588) (xy 57.1119 -164.216588) (xy 57.1119 -167.752268)
			)
		)
	)
	(zone
		(layer "F.Cu")
		(hatch none 0.5)
		(connect_pads
			(clearance 0)
		)
		(min_thickness 0.25)
		(keepout
			(tracks allowed)
			(vias allowed)
			(pads allowed)
			(copperpour allowed)
			(footprints allowed)
		)
		(placement
			(enabled no)
			(sheetname "")
		)
		(fill
			(thermal_gap 0.5)
			(thermal_bridge_width 0.5)
			(island_removal_mode 0)
		)
		(polygon
			(pts
				(xy 364.998 -399.151348) (xy 364.998 -398.109948) (xy 366.5474 -398.109948) (xy 366.5474 -399.151348)
			)
		)
	)
	(zone
		(layer "F.Cu")
		(hatch none 0.5)
		(connect_pads
			(clearance 0)
		)
		(min_thickness 0.25)
		(keepout
			(tracks allowed)
			(vias allowed)
			(pads allowed)
			(copperpour allowed)
			(footprints allowed)
		)
		(placement
			(enabled no)
			(sheetname "")
		)
		(fill
			(thermal_gap 0.5)
			(thermal_bridge_width 0.5)
			(island_removal_mode 0)
		)
		(polygon
			(pts
				(xy 385.3815 -285.745428) (xy 385.66852 -285.745428) (xy 385.699 -285.714948) (xy 385.699 -285.087568)
				(xy 385.61264 -285.001208) (xy 385.42468 -285.001208) (xy 385.35102 -285.074868) (xy 385.35102 -285.714948)
			)
		)
	)
	(zone
		(layer "F.Cu")
		(hatch none 0.5)
		(connect_pads
			(clearance 0)
		)
		(min_thickness 0.25)
		(keepout
			(tracks allowed)
			(vias allowed)
			(pads allowed)
			(copperpour allowed)
			(footprints allowed)
		)
		(placement
			(enabled no)
			(sheetname "")
		)
		(fill
			(thermal_gap 0.5)
			(thermal_bridge_width 0.5)
			(island_removal_mode 0)
		)
		(polygon
			(pts
				(xy 180.423058 -302.405034) (xy 180.423058 -302.176434) (xy 182.455058 -302.176434) (xy 182.455058 -302.405034)
			)
		)
	)
	(zone
		(layer "F.Cu")
		(hatch none 0.5)
		(connect_pads
			(clearance 0)
		)
		(min_thickness 0.25)
		(keepout
			(tracks not_allowed)
			(vias allowed)
			(pads allowed)
			(copperpour not_allowed)
			(footprints allowed)
		)
		(placement
			(enabled no)
			(sheetname "")
		)
		(fill
			(thermal_gap 0.5)
			(thermal_bridge_width 0.5)
			(island_removal_mode 0)
		)
		(polygon
			(pts
				(xy 297.42892 -411.9245) (xy 297.42892 -411.74924) (xy 299.43044 -411.74924) (xy 299.43044 -411.9245)
			)
		)
	)
	(zone
		(layer "F.Cu")
		(hatch none 0.5)
		(connect_pads
			(clearance 0)
		)
		(min_thickness 0.25)
		(keepout
			(tracks allowed)
			(vias allowed)
			(pads allowed)
			(copperpour allowed)
			(footprints allowed)
		)
		(placement
			(enabled no)
			(sheetname "")
		)
		(fill
			(thermal_gap 0.5)
			(thermal_bridge_width 0.5)
			(island_removal_mode 0)
		)
		(polygon
			(pts
				(xy 41.29151 -196.266562) (xy 41.29151 -195.822824) (xy 43.616626 -195.822824) (xy 43.616626 -196.266562)
			)
		)
	)
	(zone
		(layer "F.Cu")
		(hatch none 0.5)
		(connect_pads
			(clearance 0)
		)
		(min_thickness 0.25)
		(keepout
			(tracks allowed)
			(vias allowed)
			(pads allowed)
			(copperpour allowed)
			(footprints allowed)
		)
		(placement
			(enabled no)
			(sheetname "")
		)
		(fill
			(thermal_gap 0.5)
			(thermal_bridge_width 0.5)
			(island_removal_mode 0)
		)
		(polygon
			(pts
				(xy 157.791658 -273.276314) (xy 159.823658 -273.276314) (xy 159.823658 -273.2786) (xy 159.96158 -273.2786)
				(xy 159.96158 -273.559016) (xy 159.96158 -274.06854) (xy 158.050992 -274.06854) (xy 158.050992 -274.354036)
				(xy 157.587696 -274.354036) (xy 157.515052 -274.354036) (xy 157.515052 -273.276314) (xy 157.587696 -273.276314)
				(xy 157.668976 -273.276314)
			)
		)
	)
	(zone
		(layer "F.Cu")
		(hatch none 0.5)
		(connect_pads
			(clearance 0)
		)
		(min_thickness 0.25)
		(keepout
			(tracks allowed)
			(vias allowed)
			(pads allowed)
			(copperpour allowed)
			(footprints allowed)
		)
		(placement
			(enabled no)
			(sheetname "")
		)
		(fill
			(thermal_gap 0.5)
			(thermal_bridge_width 0.5)
			(island_removal_mode 0)
		)
		(polygon
			(pts
				(xy 289.231832 -238.76635) (xy 289.231832 -238.322612) (xy 291.556948 -238.322612) (xy 291.556948 -238.76635)
			)
		)
	)
	(zone
		(layer "F.Cu")
		(hatch none 0.5)
		(connect_pads
			(clearance 0)
		)
		(min_thickness 0.25)
		(keepout
			(tracks allowed)
			(vias allowed)
			(pads allowed)
			(copperpour allowed)
			(footprints allowed)
		)
		(placement
			(enabled no)
			(sheetname "")
		)
		(fill
			(thermal_gap 0.5)
			(thermal_bridge_width 0.5)
			(island_removal_mode 0)
		)
		(polygon
			(pts
				(xy 311.94248 -245.566438) (xy 311.94248 -245.1227) (xy 314.12688 -245.1227) (xy 314.12688 -245.566438)
			)
		)
	)
	(zone
		(layer "F.Cu")
		(hatch none 0.5)
		(connect_pads
			(clearance 0)
		)
		(min_thickness 0.25)
		(keepout
			(tracks allowed)
			(vias allowed)
			(pads allowed)
			(copperpour allowed)
			(footprints allowed)
		)
		(placement
			(enabled no)
			(sheetname "")
		)
		(fill
			(thermal_gap 0.5)
			(thermal_bridge_width 0.5)
			(island_removal_mode 0)
		)
		(polygon
			(pts
				(xy 110.78591 -331.689456) (xy 110.78591 -335.695036) (xy 111.26597 -336.175096) (xy 113.33099 -336.175096)
				(xy 113.60277 -335.903316) (xy 113.60277 -334.049116) (xy 113.85423 -333.797656) (xy 115.77447 -333.797656)
				(xy 116.19103 -333.381096) (xy 116.19103 -331.890116) (xy 115.54333 -331.242416) (xy 111.23295 -331.242416)
			)
		)
	)
	(zone
		(layer "F.Cu")
		(hatch none 0.5)
		(connect_pads
			(clearance 0)
		)
		(min_thickness 0.25)
		(keepout
			(tracks allowed)
			(vias allowed)
			(pads allowed)
			(copperpour allowed)
			(footprints allowed)
		)
		(placement
			(enabled no)
			(sheetname "")
		)
		(fill
			(thermal_gap 0.5)
			(thermal_bridge_width 0.5)
			(island_removal_mode 0)
		)
		(polygon
			(pts
				(xy 307.76291 -250.666504) (xy 307.76291 -250.222766) (xy 310.088026 -250.222766) (xy 310.088026 -250.666504)
			)
		)
	)
	(zone
		(layer "F.Cu")
		(hatch none 0.5)
		(connect_pads
			(clearance 0)
		)
		(min_thickness 0.25)
		(keepout
			(tracks allowed)
			(vias allowed)
			(pads allowed)
			(copperpour allowed)
			(footprints allowed)
		)
		(placement
			(enabled no)
			(sheetname "")
		)
		(fill
			(thermal_gap 0.5)
			(thermal_bridge_width 0.5)
			(island_removal_mode 0)
		)
		(polygon
			(pts
				(xy 93.471492 -404.802594) (xy 93.471492 -399.959576) (xy 95.355918 -399.959576) (xy 95.355918 -404.802594)
			)
		)
	)
	(zone
		(layer "F.Cu")
		(hatch none 0.5)
		(connect_pads
			(clearance 0)
		)
		(min_thickness 0.25)
		(keepout
			(tracks allowed)
			(vias allowed)
			(pads allowed)
			(copperpour allowed)
			(footprints allowed)
		)
		(placement
			(enabled no)
			(sheetname "")
		)
		(fill
			(thermal_gap 0.5)
			(thermal_bridge_width 0.5)
			(island_removal_mode 0)
		)
		(polygon
			(pts
				(xy 289.231578 -306.766468) (xy 289.231578 -306.32273) (xy 291.556694 -306.32273) (xy 291.556694 -306.766468)
			)
		)
	)
	(zone
		(layer "F.Cu")
		(hatch none 0.5)
		(connect_pads
			(clearance 0)
		)
		(min_thickness 0.25)
		(keepout
			(tracks not_allowed)
			(vias allowed)
			(pads allowed)
			(copperpour not_allowed)
			(footprints allowed)
		)
		(placement
			(enabled no)
			(sheetname "")
		)
		(fill
			(thermal_gap 0.5)
			(thermal_bridge_width 0.5)
			(island_removal_mode 0)
		)
		(polygon
			(pts
				(arc
					(start 62.782958 -48.64989)
					(mid 61.183012 -47.049944)
					(end 62.782958 -45.449998)
				)
				(arc
					(start 64.382904 -45.449998)
					(mid 65.98285 -47.049944)
					(end 64.382904 -48.64989)
				)
			)
		)
	)
	(zone
		(layer "F.Cu")
		(hatch none 0.5)
		(connect_pads
			(clearance 0)
		)
		(min_thickness 0.25)
		(keepout
			(tracks allowed)
			(vias allowed)
			(pads allowed)
			(copperpour allowed)
			(footprints allowed)
		)
		(placement
			(enabled no)
			(sheetname "")
		)
		(fill
			(thermal_gap 0.5)
			(thermal_bridge_width 0.5)
			(island_removal_mode 0)
		)
		(polygon
			(pts
				(xy 44.735242 -214.96655) (xy 44.735242 -214.522812) (xy 47.060358 -214.522812) (xy 47.060358 -214.96655)
			)
		)
	)
	(zone
		(layer "F.Cu")
		(hatch none 0.5)
		(connect_pads
			(clearance 0)
		)
		(min_thickness 0.25)
		(keepout
			(tracks allowed)
			(vias allowed)
			(pads allowed)
			(copperpour allowed)
			(footprints allowed)
		)
		(placement
			(enabled no)
			(sheetname "")
		)
		(fill
			(thermal_gap 0.5)
			(thermal_bridge_width 0.5)
			(island_removal_mode 0)
		)
		(polygon
			(pts
				(xy 262.50011 -295.716452) (xy 262.50011 -295.272714) (xy 264.825226 -295.272714) (xy 264.825226 -295.716452)
			)
		)
	)
	(zone
		(layer "F.Cu")
		(hatch none 0.5)
		(connect_pads
			(clearance 0)
		)
		(min_thickness 0.25)
		(keepout
			(tracks allowed)
			(vias allowed)
			(pads allowed)
			(copperpour allowed)
			(footprints allowed)
		)
		(placement
			(enabled no)
			(sheetname "")
		)
		(fill
			(thermal_gap 0.5)
			(thermal_bridge_width 0.5)
			(island_removal_mode 0)
		)
		(polygon
			(pts
				(xy 292.67531 -227.716588) (xy 292.67531 -227.27285) (xy 295.000426 -227.27285) (xy 295.000426 -227.716588)
			)
		)
	)
	(zone
		(layer "F.Cu")
		(hatch none 0.5)
		(connect_pads
			(clearance 0)
		)
		(min_thickness 0.25)
		(keepout
			(tracks allowed)
			(vias allowed)
			(pads allowed)
			(copperpour allowed)
			(footprints allowed)
		)
		(placement
			(enabled no)
			(sheetname "")
		)
		(fill
			(thermal_gap 0.5)
			(thermal_bridge_width 0.5)
			(island_removal_mode 0)
		)
		(polygon
			(pts
				(xy 166.00678 -14.450568) (xy 166.00678 -11.539728) (xy 171.80306 -11.539728) (xy 171.80306 -14.450568)
			)
		)
	)
	(zone
		(layer "F.Cu")
		(hatch none 0.5)
		(connect_pads
			(clearance 0)
		)
		(min_thickness 0.25)
		(keepout
			(tracks allowed)
			(vias allowed)
			(pads allowed)
			(copperpour allowed)
			(footprints allowed)
		)
		(placement
			(enabled no)
			(sheetname "")
		)
		(fill
			(thermal_gap 0.5)
			(thermal_bridge_width 0.5)
			(island_removal_mode 0)
		)
		(polygon
			(pts
				(xy 289.231578 -310.166512) (xy 289.231578 -309.722774) (xy 291.556694 -309.722774) (xy 291.556694 -310.166512)
			)
		)
	)
	(zone
		(layer "F.Cu")
		(hatch none 0.5)
		(connect_pads
			(clearance 0)
		)
		(min_thickness 0.25)
		(keepout
			(tracks allowed)
			(vias allowed)
			(pads allowed)
			(copperpour allowed)
			(footprints allowed)
		)
		(placement
			(enabled no)
			(sheetname "")
		)
		(fill
			(thermal_gap 0.5)
			(thermal_bridge_width 0.5)
			(island_removal_mode 0)
		)
		(polygon
			(pts
				(xy 195.510658 -245.454932) (xy 195.510658 -245.226332) (xy 197.542658 -245.226332) (xy 197.542658 -245.454932)
			)
		)
	)
	(zone
		(layer "F.Cu")
		(hatch none 0.5)
		(connect_pads
			(clearance 0)
		)
		(min_thickness 0.25)
		(keepout
			(tracks allowed)
			(vias allowed)
			(pads allowed)
			(copperpour allowed)
			(footprints allowed)
		)
		(placement
			(enabled no)
			(sheetname "")
		)
		(fill
			(thermal_gap 0.5)
			(thermal_bridge_width 0.5)
			(island_removal_mode 0)
		)
		(polygon
			(pts
				(xy 180.423058 -293.05504) (xy 180.423058 -292.82644) (xy 182.455058 -292.82644) (xy 182.455058 -293.05504)
			)
		)
	)
	(zone
		(layer "F.Cu")
		(hatch none 0.5)
		(connect_pads
			(clearance 0)
		)
		(min_thickness 0.25)
		(keepout
			(tracks allowed)
			(vias allowed)
			(pads allowed)
			(copperpour allowed)
			(footprints allowed)
		)
		(placement
			(enabled no)
			(sheetname "")
		)
		(fill
			(thermal_gap 0.5)
			(thermal_bridge_width 0.5)
			(island_removal_mode 0)
		)
		(polygon
			(pts
				(xy 133.297168 -410.948886) (xy 133.297168 -406.105868) (xy 135.181594 -406.105868) (xy 135.181594 -410.948886)
			)
		)
	)
	(zone
		(layer "F.Cu")
		(hatch none 0.5)
		(connect_pads
			(clearance 0)
		)
		(min_thickness 0.25)
		(keepout
			(tracks allowed)
			(vias allowed)
			(pads allowed)
			(copperpour allowed)
			(footprints allowed)
		)
		(placement
			(enabled no)
			(sheetname "")
		)
		(fill
			(thermal_gap 0.5)
			(thermal_bridge_width 0.5)
			(island_removal_mode 0)
		)
		(polygon
			(pts
				(xy 440.006994 -249.47626) (xy 442.038994 -249.47626) (xy 442.038994 -249.70486) (xy 440.006994 -249.70486)
				(xy 439.84037 -249.70486) (xy 439.84037 -249.47626)
			)
		)
	)
	(zone
		(layer "F.Cu")
		(hatch none 0.5)
		(connect_pads
			(clearance 0)
		)
		(min_thickness 0.25)
		(keepout
			(tracks allowed)
			(vias allowed)
			(pads allowed)
			(copperpour allowed)
			(footprints allowed)
		)
		(placement
			(enabled no)
			(sheetname "")
		)
		(fill
			(thermal_gap 0.5)
			(thermal_bridge_width 0.5)
			(island_removal_mode 0)
		)
		(polygon
			(pts
				(xy 210.598258 -287.954974) (xy 210.598258 -287.726374) (xy 212.630258 -287.726374) (xy 212.630258 -287.954974)
			)
		)
	)
	(zone
		(layer "F.Cu")
		(hatch none 0.5)
		(connect_pads
			(clearance 0)
		)
		(min_thickness 0.25)
		(keepout
			(tracks allowed)
			(vias allowed)
			(pads allowed)
			(copperpour allowed)
			(footprints allowed)
		)
		(placement
			(enabled no)
			(sheetname "")
		)
		(fill
			(thermal_gap 0.5)
			(thermal_bridge_width 0.5)
			(island_removal_mode 0)
		)
		(polygon
			(pts
				(xy 424.919394 -312.606944) (xy 426.951394 -312.606944) (xy 426.951394 -312.378344) (xy 424.919394 -312.378344)
				(xy 424.788076 -312.378344) (xy 424.762168 -312.378344) (xy 424.762168 -312.606944) (xy 424.788076 -312.606944)
			)
		)
	)
	(zone
		(layer "F.Cu")
		(hatch none 0.5)
		(connect_pads
			(clearance 0)
		)
		(min_thickness 0.25)
		(keepout
			(tracks allowed)
			(vias allowed)
			(pads allowed)
			(copperpour allowed)
			(footprints allowed)
		)
		(placement
			(enabled no)
			(sheetname "")
		)
		(fill
			(thermal_gap 0.5)
			(thermal_bridge_width 0.5)
			(island_removal_mode 0)
		)
		(polygon
			(pts
				(xy 262.50011 -236.216444) (xy 262.50011 -235.772706) (xy 264.825226 -235.772706) (xy 264.825226 -236.216444)
			)
		)
	)
	(zone
		(layer "F.Cu")
		(hatch none 0.5)
		(connect_pads
			(clearance 0)
		)
		(min_thickness 0.25)
		(keepout
			(tracks allowed)
			(vias allowed)
			(pads allowed)
			(copperpour allowed)
			(footprints allowed)
		)
		(placement
			(enabled no)
			(sheetname "")
		)
		(fill
			(thermal_gap 0.5)
			(thermal_bridge_width 0.5)
			(island_removal_mode 0)
		)
		(polygon
			(pts
				(xy 11.11631 -203.916534) (xy 11.11631 -203.472796) (xy 13.441426 -203.472796) (xy 13.441426 -203.916534)
			)
		)
	)
	(zone
		(layer "F.Cu")
		(hatch none 0.5)
		(connect_pads
			(clearance 0)
		)
		(min_thickness 0.25)
		(keepout
			(tracks allowed)
			(vias allowed)
			(pads allowed)
			(copperpour allowed)
			(footprints not_allowed)
		)
		(placement
			(enabled no)
			(sheetname "")
		)
		(fill
			(thermal_gap 0.5)
			(thermal_bridge_width 0.5)
			(island_removal_mode 0)
		)
		(polygon
			(pts
				(arc
					(start 295.900094 -26.566876)
					(mid 302.400117 -33.999932)
					(end 295.900094 -41.432988)
				)
			)
		)
	)
	(zone
		(layer "F.Cu")
		(hatch none 0.5)
		(connect_pads
			(clearance 0)
		)
		(min_thickness 0.25)
		(keepout
			(tracks allowed)
			(vias allowed)
			(pads allowed)
			(copperpour allowed)
			(footprints not_allowed)
		)
		(placement
			(enabled no)
			(sheetname "")
		)
		(fill
			(thermal_gap 0.5)
			(thermal_bridge_width 0.5)
			(island_removal_mode 0)
		)
		(polygon
			(pts
				(xy 112.15497 -68.49999) (xy 112.15497 -73.000108) (xy 134.22503 -73.000108) (xy 134.22503 -68.49999)
			)
		)
	)
	(zone
		(layer "F.Cu")
		(hatch none 0.5)
		(connect_pads
			(clearance 0)
		)
		(min_thickness 0.25)
		(keepout
			(tracks allowed)
			(vias allowed)
			(pads allowed)
			(copperpour allowed)
			(footprints allowed)
		)
		(placement
			(enabled no)
			(sheetname "")
		)
		(fill
			(thermal_gap 0.5)
			(thermal_bridge_width 0.5)
			(island_removal_mode 0)
		)
		(polygon
			(pts
				(xy 59.822842 -205.616556) (xy 59.822842 -205.172818) (xy 62.147958 -205.172818) (xy 62.147958 -205.616556)
			)
		)
	)
	(zone
		(layer "F.Cu")
		(hatch none 0.5)
		(connect_pads
			(clearance 0)
		)
		(min_thickness 0.25)
		(keepout
			(tracks allowed)
			(vias allowed)
			(pads allowed)
			(copperpour allowed)
			(footprints allowed)
		)
		(placement
			(enabled no)
			(sheetname "")
		)
		(fill
			(thermal_gap 0.5)
			(thermal_bridge_width 0.5)
			(island_removal_mode 0)
		)
		(polygon
			(pts
				(xy 165.335458 -252.25502) (xy 165.335458 -252.02642) (xy 167.367458 -252.02642) (xy 167.367458 -252.25502)
			)
		)
	)
	(zone
		(layer "F.Cu")
		(hatch none 0.5)
		(connect_pads
			(clearance 0)
		)
		(min_thickness 0.25)
		(keepout
			(tracks allowed)
			(vias allowed)
			(pads allowed)
			(copperpour allowed)
			(footprints allowed)
		)
		(placement
			(enabled no)
			(sheetname "")
		)
		(fill
			(thermal_gap 0.5)
			(thermal_bridge_width 0.5)
			(island_removal_mode 0)
		)
		(polygon
			(pts
				(xy 195.510658 -292.204902) (xy 195.510658 -291.976302) (xy 197.542658 -291.976302) (xy 197.542658 -292.204902)
			)
		)
	)
	(zone
		(layer "F.Cu")
		(hatch none 0.5)
		(connect_pads
			(clearance 0)
		)
		(min_thickness 0.25)
		(keepout
			(tracks allowed)
			(vias allowed)
			(pads allowed)
			(copperpour allowed)
			(footprints allowed)
		)
		(placement
			(enabled no)
			(sheetname "")
		)
		(fill
			(thermal_gap 0.5)
			(thermal_bridge_width 0.5)
			(island_removal_mode 0)
		)
		(polygon
			(pts
				(xy 455.094594 -212.926422) (xy 457.126594 -212.926422) (xy 457.126594 -213.155022) (xy 455.094594 -213.155022)
				(xy 454.95845 -213.155022) (xy 454.91146 -213.155022) (xy 454.91146 -212.926422) (xy 454.95845 -212.926422)
			)
		)
	)
	(zone
		(layer "F.Cu")
		(hatch none 0.5)
		(connect_pads
			(clearance 0)
		)
		(min_thickness 0.25)
		(keepout
			(tracks allowed)
			(vias allowed)
			(pads allowed)
			(copperpour allowed)
			(footprints allowed)
		)
		(placement
			(enabled no)
			(sheetname "")
		)
		(fill
			(thermal_gap 0.5)
			(thermal_bridge_width 0.5)
			(island_removal_mode 0)
		)
		(polygon
			(pts
				(xy 455.094594 -223.976438) (xy 457.126594 -223.976438) (xy 457.126594 -224.205038) (xy 455.094594 -224.205038)
				(xy 454.95845 -224.205038) (xy 454.91146 -224.205038) (xy 454.91146 -223.976438) (xy 454.95845 -223.976438)
			)
		)
	)
	(zone
		(layer "F.Cu")
		(hatch none 0.5)
		(connect_pads
			(clearance 0)
		)
		(min_thickness 0.25)
		(keepout
			(tracks allowed)
			(vias allowed)
			(pads allowed)
			(copperpour allowed)
			(footprints allowed)
		)
		(placement
			(enabled no)
			(sheetname "")
		)
		(fill
			(thermal_gap 0.5)
			(thermal_bridge_width 0.5)
			(island_removal_mode 0)
		)
		(polygon
			(pts
				(xy 387.290564 -240.087912) (xy 387.49351 -239.884966) (xy 387.49351 -239.84204) (xy 387.050026 -239.398302)
				(xy 386.927852 -239.398302) (xy 386.794756 -239.531144) (xy 386.794756 -239.635284) (xy 387.247384 -240.087912)
			)
		)
	)
	(zone
		(layer "F.Cu")
		(hatch none 0.5)
		(connect_pads
			(clearance 0)
		)
		(min_thickness 0.25)
		(keepout
			(tracks allowed)
			(vias allowed)
			(pads allowed)
			(copperpour allowed)
			(footprints allowed)
		)
		(placement
			(enabled no)
			(sheetname "")
		)
		(fill
			(thermal_gap 0.5)
			(thermal_bridge_width 0.5)
			(island_removal_mode 0)
		)
		(polygon
			(pts
				(xy 384.565144 -410.948886) (xy 384.565144 -406.105868) (xy 386.44957 -406.105868) (xy 386.44957 -410.948886)
			)
		)
	)
	(zone
		(layer "F.Cu")
		(hatch none 0.5)
		(connect_pads
			(clearance 0)
		)
		(min_thickness 0.25)
		(keepout
			(tracks allowed)
			(vias allowed)
			(pads allowed)
			(copperpour allowed)
			(footprints allowed)
		)
		(placement
			(enabled no)
			(sheetname "")
		)
		(fill
			(thermal_gap 0.5)
			(thermal_bridge_width 0.5)
			(island_removal_mode 0)
		)
		(polygon
			(pts
				(xy 59.822842 -292.316662) (xy 59.822842 -291.872924) (xy 62.147958 -291.872924) (xy 62.147958 -292.316662)
			)
		)
	)
	(zone
		(layer "F.Cu")
		(hatch none 0.5)
		(connect_pads
			(clearance 0)
		)
		(min_thickness 0.25)
		(keepout
			(tracks allowed)
			(vias allowed)
			(pads allowed)
			(copperpour allowed)
			(footprints allowed)
		)
		(placement
			(enabled no)
			(sheetname "")
		)
		(fill
			(thermal_gap 0.5)
			(thermal_bridge_width 0.5)
			(island_removal_mode 0)
		)
		(polygon
			(pts
				(xy 139.295378 -230.283766) (xy 139.498324 -230.08082) (xy 139.498324 -230.03764) (xy 139.054586 -229.593902)
				(xy 138.932412 -229.593902) (xy 138.79957 -229.726998) (xy 138.79957 -229.831138) (xy 139.252198 -230.283766)
			)
		)
	)
	(zone
		(layer "F.Cu")
		(hatch none 0.5)
		(connect_pads
			(clearance 0)
		)
		(min_thickness 0.25)
		(keepout
			(tracks allowed)
			(vias allowed)
			(pads allowed)
			(copperpour allowed)
			(footprints allowed)
		)
		(placement
			(enabled no)
			(sheetname "")
		)
		(fill
			(thermal_gap 0.5)
			(thermal_bridge_width 0.5)
			(island_removal_mode 0)
		)
		(polygon
			(pts
				(xy 387.628384 -410.948886) (xy 387.628384 -406.105868) (xy 389.51281 -406.105868) (xy 389.51281 -410.948886)
			)
		)
	)
	(zone
		(layer "F.Cu")
		(hatch none 0.5)
		(connect_pads
			(clearance 0)
		)
		(min_thickness 0.25)
		(keepout
			(tracks allowed)
			(vias allowed)
			(pads allowed)
			(copperpour allowed)
			(footprints allowed)
		)
		(placement
			(enabled no)
			(sheetname "")
		)
		(fill
			(thermal_gap 0.5)
			(thermal_bridge_width 0.5)
			(island_removal_mode 0)
		)
		(polygon
			(pts
				(xy 150.330408 -404.802594) (xy 150.330408 -399.959576) (xy 152.214834 -399.959576) (xy 152.214834 -404.802594)
			)
		)
	)
	(zone
		(layer "F.Cu")
		(hatch none 0.5)
		(connect_pads
			(clearance 0)
		)
		(min_thickness 0.25)
		(keepout
			(tracks allowed)
			(vias allowed)
			(pads allowed)
			(copperpour allowed)
			(footprints allowed)
		)
		(placement
			(enabled no)
			(sheetname "")
		)
		(fill
			(thermal_gap 0.5)
			(thermal_bridge_width 0.5)
			(island_removal_mode 0)
		)
		(polygon
			(pts
				(xy 384.35026 -216.050368) (xy 384.63728 -216.050368) (xy 384.66776 -216.019888) (xy 384.66776 -215.392508)
				(xy 384.5814 -215.306148) (xy 384.39344 -215.306148) (xy 384.31978 -215.379808) (xy 384.31978 -216.019888)
			)
		)
	)
	(zone
		(layer "F.Cu")
		(hatch none 0.5)
		(connect_pads
			(clearance 0)
		)
		(min_thickness 0.25)
		(keepout
			(tracks allowed)
			(vias allowed)
			(pads allowed)
			(copperpour allowed)
			(footprints allowed)
		)
		(placement
			(enabled no)
			(sheetname "")
		)
		(fill
			(thermal_gap 0.5)
			(thermal_bridge_width 0.5)
			(island_removal_mode 0)
		)
		(polygon
			(pts
				(xy 161.891726 -233.326432) (xy 163.923726 -233.326432) (xy 164.086794 -233.326432) (xy 164.086794 -234.0737)
				(xy 161.720276 -234.0737) (xy 161.720276 -233.326432)
			)
		)
	)
	(zone
		(layer "F.Cu")
		(hatch none 0.5)
		(connect_pads
			(clearance 0)
		)
		(min_thickness 0.25)
		(keepout
			(tracks allowed)
			(vias allowed)
			(pads allowed)
			(copperpour allowed)
			(footprints allowed)
		)
		(placement
			(enabled no)
			(sheetname "")
		)
		(fill
			(thermal_gap 0.5)
			(thermal_bridge_width 0.5)
			(island_removal_mode 0)
		)
		(polygon
			(pts
				(xy 14.560042 -311.866534) (xy 14.560042 -311.422796) (xy 16.885158 -311.422796) (xy 16.885158 -311.866534)
			)
		)
	)
	(zone
		(layer "F.Cu")
		(hatch none 0.5)
		(connect_pads
			(clearance 0)
		)
		(min_thickness 0.25)
		(keepout
			(tracks allowed)
			(vias allowed)
			(pads allowed)
			(copperpour allowed)
			(footprints allowed)
		)
		(placement
			(enabled no)
			(sheetname "")
		)
		(fill
			(thermal_gap 0.5)
			(thermal_bridge_width 0.5)
			(island_removal_mode 0)
		)
		(polygon
			(pts
				(xy 192.066926 -261.376414) (xy 194.098926 -261.376414) (xy 194.098926 -261.605014) (xy 192.066926 -261.605014)
				(xy 191.900302 -261.605014) (xy 191.900302 -261.376414)
			)
		)
	)
	(zone
		(layer "F.Cu")
		(hatch none 0.5)
		(connect_pads
			(clearance 0)
		)
		(min_thickness 0.25)
		(keepout
			(tracks allowed)
			(vias allowed)
			(pads allowed)
			(copperpour allowed)
			(footprints allowed)
		)
		(placement
			(enabled no)
			(sheetname "")
		)
		(fill
			(thermal_gap 0.5)
			(thermal_bridge_width 0.5)
			(island_removal_mode 0)
		)
		(polygon
			(pts
				(xy 12.15136 -100.983288) (xy 12.15136 -97.318068) (xy 15.91564 -97.318068) (xy 15.91564 -100.983288)
			)
		)
	)
	(zone
		(layer "F.Cu")
		(hatch none 0.5)
		(connect_pads
			(clearance 0)
		)
		(min_thickness 0.25)
		(keepout
			(tracks allowed)
			(vias allowed)
			(pads allowed)
			(copperpour allowed)
			(footprints allowed)
		)
		(placement
			(enabled no)
			(sheetname "")
		)
		(fill
			(thermal_gap 0.5)
			(thermal_bridge_width 0.5)
			(island_removal_mode 0)
		)
		(polygon
			(pts
				(xy 443.450726 -291.355018) (xy 443.450726 -291.126418) (xy 445.482726 -291.126418) (xy 445.482726 -291.355018)
			)
		)
	)
	(zone
		(layer "F.Cu")
		(hatch none 0.5)
		(connect_pads
			(clearance 0)
		)
		(min_thickness 0.25)
		(keepout
			(tracks allowed)
			(vias allowed)
			(pads allowed)
			(copperpour allowed)
			(footprints allowed)
		)
		(placement
			(enabled no)
			(sheetname "")
		)
		(fill
			(thermal_gap 0.5)
			(thermal_bridge_width 0.5)
			(island_removal_mode 0)
		)
		(polygon
			(pts
				(xy 165.335458 -287.954974) (xy 165.335458 -287.726374) (xy 167.367458 -287.726374) (xy 167.367458 -287.954974)
			)
		)
	)
	(zone
		(layer "F.Cu")
		(hatch none 0.5)
		(connect_pads
			(clearance 0)
		)
		(min_thickness 0.25)
		(keepout
			(tracks allowed)
			(vias allowed)
			(pads allowed)
			(copperpour allowed)
			(footprints allowed)
		)
		(placement
			(enabled no)
			(sheetname "")
		)
		(fill
			(thermal_gap 0.5)
			(thermal_bridge_width 0.5)
			(island_removal_mode 0)
		)
		(polygon
			(pts
				(xy 277.58771 -208.166462) (xy 277.58771 -207.722724) (xy 279.912826 -207.722724) (xy 279.912826 -208.166462)
			)
		)
	)
	(zone
		(layer "F.Cu")
		(hatch none 0.5)
		(connect_pads
			(clearance 0)
		)
		(min_thickness 0.25)
		(keepout
			(tracks allowed)
			(vias allowed)
			(pads allowed)
			(copperpour allowed)
			(footprints allowed)
		)
		(placement
			(enabled no)
			(sheetname "")
		)
		(fill
			(thermal_gap 0.5)
			(thermal_bridge_width 0.5)
			(island_removal_mode 0)
		)
		(polygon
			(pts
				(xy 455.094594 -239.276382) (xy 457.126594 -239.276382) (xy 457.126594 -239.504982) (xy 455.094594 -239.504982)
				(xy 454.95845 -239.504982) (xy 454.91146 -239.504982) (xy 454.91146 -239.276382) (xy 454.95845 -239.276382)
			)
		)
	)
	(zone
		(layer "F.Cu")
		(hatch none 0.5)
		(connect_pads
			(clearance 0)
		)
		(min_thickness 0.25)
		(keepout
			(tracks allowed)
			(vias allowed)
			(pads allowed)
			(copperpour allowed)
			(footprints allowed)
		)
		(placement
			(enabled no)
			(sheetname "")
		)
		(fill
			(thermal_gap 0.5)
			(thermal_bridge_width 0.5)
			(island_removal_mode 0)
		)
		(polygon
			(pts
				(xy 26.20391 -211.566506) (xy 26.20391 -211.122768) (xy 28.529026 -211.122768) (xy 28.529026 -211.566506)
			)
		)
	)
	(zone
		(layer "F.Cu")
		(hatch none 0.5)
		(connect_pads
			(clearance 0)
		)
		(min_thickness 0.25)
		(keepout
			(tracks allowed)
			(vias allowed)
			(pads allowed)
			(copperpour allowed)
			(footprints not_allowed)
		)
		(placement
			(enabled no)
			(sheetname "")
		)
		(fill
			(thermal_gap 0.5)
			(thermal_bridge_width 0.5)
			(island_removal_mode 0)
		)
		(polygon
			(pts
				(xy 391.788396 -70.65518) (xy 398.011396 -70.65518)
				(arc
					(start 398.011396 -72.00011)
					(mid 413.011366 -57.00014)
					(end 398.011396 -41.999916)
				)
				(xy 398.011396 -43.344592) (xy 391.788396 -43.344592)
				(arc
					(start 391.788396 -41.999916)
					(mid 376.788172 -57.00014)
					(end 391.788396 -72.00011)
				)
			)
		)
	)
	(zone
		(layer "F.Cu")
		(hatch none 0.5)
		(connect_pads
			(clearance 0)
		)
		(min_thickness 0.25)
		(keepout
			(tracks not_allowed)
			(vias allowed)
			(pads allowed)
			(copperpour not_allowed)
			(footprints allowed)
		)
		(placement
			(enabled no)
			(sheetname "")
		)
		(fill
			(thermal_gap 0.5)
			(thermal_bridge_width 0.5)
			(island_removal_mode 0)
		)
		(polygon
			(pts
				(xy 63.068962 -11.992356) (xy 63.244222 -11.992356) (xy 63.272162 -11.964416) (xy 63.272162 -10.569956)
				(xy 63.249302 -10.547096) (xy 63.079122 -10.547096) (xy 63.058802 -10.567416) (xy 63.058802 -11.982196)
			)
		)
	)
	(zone
		(layer "F.Cu")
		(hatch none 0.5)
		(connect_pads
			(clearance 0)
		)
		(min_thickness 0.25)
		(keepout
			(tracks allowed)
			(vias allowed)
			(pads allowed)
			(copperpour allowed)
			(footprints allowed)
		)
		(placement
			(enabled no)
			(sheetname "")
		)
		(fill
			(thermal_gap 0.5)
			(thermal_bridge_width 0.5)
			(island_removal_mode 0)
		)
		(polygon
			(pts
				(xy 180.423058 -213.155022) (xy 180.423058 -212.926422) (xy 182.455058 -212.926422) (xy 182.455058 -213.155022)
			)
		)
	)
	(zone
		(layer "F.Cu")
		(hatch none 0.5)
		(connect_pads
			(clearance 0)
		)
		(min_thickness 0.25)
		(keepout
			(tracks allowed)
			(vias allowed)
			(pads allowed)
			(copperpour allowed)
			(footprints allowed)
		)
		(placement
			(enabled no)
			(sheetname "")
		)
		(fill
			(thermal_gap 0.5)
			(thermal_bridge_width 0.5)
			(island_removal_mode 0)
		)
		(polygon
			(pts
				(xy 335.182464 -277.471632) (xy 335.38541 -277.268686) (xy 335.38541 -277.22576) (xy 334.941926 -276.782022)
				(xy 334.819752 -276.782022) (xy 334.686656 -276.914864) (xy 334.686656 -277.019004) (xy 335.139284 -277.471632)
			)
		)
	)
	(zone
		(layer "F.Cu")
		(hatch none 0.5)
		(connect_pads
			(clearance 0)
		)
		(min_thickness 0.25)
		(keepout
			(tracks allowed)
			(vias allowed)
			(pads allowed)
			(copperpour allowed)
			(footprints allowed)
		)
		(placement
			(enabled no)
			(sheetname "")
		)
		(fill
			(thermal_gap 0.5)
			(thermal_bridge_width 0.5)
			(island_removal_mode 0)
		)
		(polygon
			(pts
				(xy 29.647642 -305.916584) (xy 29.647642 -305.472846) (xy 31.972758 -305.472846) (xy 31.972758 -305.916584)
			)
		)
	)
	(zone
		(layer "F.Cu")
		(hatch none 0.5)
		(connect_pads
			(clearance 0)
		)
		(min_thickness 0.25)
		(keepout
			(tracks allowed)
			(vias allowed)
			(pads allowed)
			(copperpour allowed)
			(footprints allowed)
		)
		(placement
			(enabled no)
			(sheetname "")
		)
		(fill
			(thermal_gap 0.5)
			(thermal_bridge_width 0.5)
			(island_removal_mode 0)
		)
		(polygon
			(pts
				(xy 206.896462 -319.243202) (xy 206.896462 -316.881002) (xy 209.512662 -316.881002) (xy 209.512662 -319.243202)
			)
		)
	)
	(zone
		(layer "F.Cu")
		(hatch none 0.5)
		(connect_pads
			(clearance 0)
		)
		(min_thickness 0.25)
		(keepout
			(tracks not_allowed)
			(vias allowed)
			(pads allowed)
			(copperpour not_allowed)
			(footprints allowed)
		)
		(placement
			(enabled no)
			(sheetname "")
		)
		(fill
			(thermal_gap 0.5)
			(thermal_bridge_width 0.5)
			(island_removal_mode 0)
		)
		(polygon
			(pts
				(arc
					(start 466.459824 -160.50006)
					(mid 461.459834 -165.50005)
					(end 456.459844 -160.50006)
				)
				(arc
					(start 456.459844 -160.50006)
					(mid 461.459834 -155.50007)
					(end 466.459824 -160.50006)
				)
			)
		)
	)
	(zone
		(layer "F.Cu")
		(hatch none 0.5)
		(connect_pads
			(clearance 0)
		)
		(min_thickness 0.25)
		(keepout
			(tracks allowed)
			(vias allowed)
			(pads allowed)
			(copperpour allowed)
			(footprints allowed)
		)
		(placement
			(enabled no)
			(sheetname "")
		)
		(fill
			(thermal_gap 0.5)
			(thermal_bridge_width 0.5)
			(island_removal_mode 0)
		)
		(polygon
			(pts
				(xy 262.50011 -305.916584) (xy 262.50011 -305.472846) (xy 264.825226 -305.472846) (xy 264.825226 -305.916584)
			)
		)
	)
	(zone
		(layer "F.Cu")
		(hatch none 0.5)
		(connect_pads
			(clearance 0)
		)
		(min_thickness 0.25)
		(keepout
			(tracks allowed)
			(vias allowed)
			(pads allowed)
			(copperpour allowed)
			(footprints not_allowed)
		)
		(placement
			(enabled no)
			(sheetname "")
		)
		(fill
			(thermal_gap 0.5)
			(thermal_bridge_width 0.5)
			(island_removal_mode 0)
		)
		(polygon
			(pts
				(arc
					(start 49.126394 -51.049936)
					(mid 58.741202 -61.246827)
					(end 72.58304 -59.04992)
				)
				(arc
					(start 84.583016 -59.04992)
					(mid 93.58315 -62.050016)
					(end 102.583234 -59.04992)
				)
				(arc
					(start 104.58323 -59.04992)
					(mid 113.583212 -62.049914)
					(end 122.583194 -59.04992)
				)
				(arc
					(start 122.583194 -59.04992)
					(mid 126.839769 -61.280165)
					(end 131.583176 -62.049914)
				)
				(arc
					(start 131.583176 -62.049914)
					(mid 134.647805 -61.733511)
					(end 137.583164 -60.797694)
				)
				(arc
					(start 137.583164 -60.797694)
					(mid 145.319147 -61.949166)
					(end 152.583134 -59.04992)
				)
				(xy 168.283128 -59.04992) (xy 168.283128 -58.97499) (xy 178.433222 -58.97499) (xy 178.433222 -35.124898)
				(xy 168.283128 -35.124898) (xy 168.283128 -35.049968)
				(arc
					(start 152.583134 -35.049968)
					(mid 145.319142 -32.150768)
					(end 137.583164 -33.302194)
				)
				(arc
					(start 137.583164 -33.302194)
					(mid 134.647814 -32.366331)
					(end 131.583176 -32.049974)
				)
				(arc
					(start 131.583176 -32.049974)
					(mid 126.839769 -32.819723)
					(end 122.583194 -35.049968)
				)
				(arc
					(start 122.583194 -35.049968)
					(mid 113.583212 -32.049974)
					(end 104.58323 -35.049968)
				)
				(arc
					(start 102.583234 -35.049968)
					(mid 93.58315 -32.050025)
					(end 84.583016 -35.049968)
				)
				(arc
					(start 72.58304 -35.049968)
					(mid 58.741159 -32.852933)
					(end 49.126394 -43.049952)
				)
				(xy 40.583104 -43.049952) (xy 40.583104 -51.049936)
			)
		)
	)
	(zone
		(layer "F.Cu")
		(hatch none 0.5)
		(connect_pads
			(clearance 0)
		)
		(min_thickness 0.25)
		(keepout
			(tracks allowed)
			(vias allowed)
			(pads allowed)
			(copperpour allowed)
			(footprints allowed)
		)
		(placement
			(enabled no)
			(sheetname "")
		)
		(fill
			(thermal_gap 0.5)
			(thermal_bridge_width 0.5)
			(island_removal_mode 0)
		)
		(polygon
			(pts
				(xy 139.587478 -262.85317) (xy 139.384532 -262.650224) (xy 139.341352 -262.650224) (xy 138.897614 -263.093962)
				(xy 138.897614 -263.216136) (xy 139.03071 -263.348978) (xy 139.13485 -263.348978) (xy 139.587478 -262.89635)
			)
		)
	)
	(zone
		(layer "F.Cu")
		(hatch none 0.5)
		(connect_pads
			(clearance 0)
		)
		(min_thickness 0.25)
		(keepout
			(tracks allowed)
			(vias allowed)
			(pads allowed)
			(copperpour allowed)
			(footprints allowed)
		)
		(placement
			(enabled no)
			(sheetname "")
		)
		(fill
			(thermal_gap 0.5)
			(thermal_bridge_width 0.5)
			(island_removal_mode 0)
		)
		(polygon
			(pts
				(xy 29.647642 -197.116446) (xy 29.647642 -196.672708) (xy 31.972758 -196.672708) (xy 31.972758 -197.116446)
			)
		)
	)
	(zone
		(layer "F.Cu")
		(hatch none 0.5)
		(connect_pads
			(clearance 0)
		)
		(min_thickness 0.25)
		(keepout
			(tracks allowed)
			(vias allowed)
			(pads allowed)
			(copperpour allowed)
			(footprints allowed)
		)
		(placement
			(enabled no)
			(sheetname "")
		)
		(fill
			(thermal_gap 0.5)
			(thermal_bridge_width 0.5)
			(island_removal_mode 0)
		)
		(polygon
			(pts
				(xy 304.319178 -313.566556) (xy 304.319178 -313.122818) (xy 306.644294 -313.122818) (xy 306.644294 -313.566556)
			)
		)
	)
	(zone
		(layer "F.Cu")
		(hatch none 0.5)
		(connect_pads
			(clearance 0)
		)
		(min_thickness 0.25)
		(keepout
			(tracks allowed)
			(vias allowed)
			(pads allowed)
			(copperpour allowed)
			(footprints allowed)
		)
		(placement
			(enabled no)
			(sheetname "")
		)
		(fill
			(thermal_gap 0.5)
			(thermal_bridge_width 0.5)
			(island_removal_mode 0)
		)
		(polygon
			(pts
				(xy 335.521554 -290.103814) (xy 355.588062 -290.10356) (xy 355.588062 -290.060126) (xy 359.197402 -290.060126)
				(xy 359.197402 -290.10356) (xy 385.73202 -290.103052) (xy 386.78866 -289.046412) (xy 386.78866 -280.788872)
				(xy 386.373878 -280.37409) (xy 385.680712 -280.37409) (xy 384.313176 -279.006554) (xy 384.312922 -275.18995)
				(xy 383.84734 -274.724368) (xy 383.84734 -253.718314) (xy 383.582672 -253.453646) (xy 383.14376 -253.014734)
				(xy 381.822198 -253.014734) (xy 381.136906 -252.329442) (xy 379.983238 -251.175774) (xy 379.983238 -248.675398)
				(xy 380.811532 -247.847104) (xy 382.843532 -247.847104) (xy 383.750566 -246.94007) (xy 383.750058 -227.200206)
				(xy 385.74726 -225.203004) (xy 386.938774 -225.203004) (xy 387.140958 -225.00082) (xy 387.140958 -218.525344)
				(xy 386.81025 -218.194636) (xy 386.809996 -215.543638) (xy 384.509264 -213.242906) (xy 359.196132 -213.243414)
				(xy 355.586792 -213.243414) (xy 336.875374 -213.243668) (xy 334.687926 -215.431116) (xy 334.44942 -215.669622)
				(xy 333.497174 -215.669622) (xy 333.353156 -215.813386) (xy 333.35341 -217.634312) (xy 334.379316 -218.660218)
				(xy 334.764126 -218.660218) (xy 335.819496 -219.715588) (xy 335.819496 -222.477076) (xy 335.355946 -222.940626)
				(xy 332.98892 -222.940626) (xy 332.337918 -223.591628) (xy 332.337918 -227.398072) (xy 332.909926 -227.97008)
				(xy 334.33004 -227.97008) (xy 335.903062 -229.543102) (xy 335.90357 -250.594114) (xy 334.833722 -251.663962)
				(xy 334.833722 -253.868682) (xy 335.957926 -254.992886) (xy 335.95818 -268.515084) (xy 334.99171 -269.481554)
				(xy 334.99171 -270.280638) (xy 335.445862 -270.73479) (xy 335.445862 -271.091152) (xy 335.943448 -271.588738)
				(xy 335.943448 -273.424904) (xy 334.442308 -274.926044) (xy 334.442308 -275.3995) (xy 334.856836 -275.813774)
				(xy 335.87817 -275.813774) (xy 337.04149 -276.977094) (xy 337.603592 -276.977094) (xy 338.367878 -277.74138)
				(xy 338.367878 -278.160734) (xy 338.190332 -278.33828) (xy 336.545936 -278.33828) (xy 336.399886 -278.48433)
				(xy 336.399886 -278.849582) (xy 336.01533 -279.234138) (xy 335.692242 -279.234138) (xy 335.149698 -279.234138)
				(xy 335.04124 -279.342596) (xy 334.518508 -279.342596) (xy 334.400144 -279.224232) (xy 334.143858 -279.224232)
				(xy 334.045306 -279.322784) (xy 334.045306 -279.659334) (xy 333.575406 -280.129234) (xy 333.575406 -281.52852)
				(xy 333.042006 -282.06192) (xy 333.042006 -287.62452)
			)
		)
	)
	(zone
		(layer "F.Cu")
		(hatch none 0.5)
		(connect_pads
			(clearance 0)
		)
		(min_thickness 0.25)
		(keepout
			(tracks allowed)
			(vias allowed)
			(pads allowed)
			(copperpour allowed)
			(footprints allowed)
		)
		(placement
			(enabled no)
			(sheetname "")
		)
		(fill
			(thermal_gap 0.5)
			(thermal_bridge_width 0.5)
			(island_removal_mode 0)
		)
		(polygon
			(pts
				(xy 310.088026 -241.31651) (xy 307.76291 -241.31651) (xy 307.632862 -241.31651) (xy 307.632862 -240.394744)
				(xy 310.153558 -240.394744) (xy 310.153558 -241.31651)
			)
		)
	)
	(zone
		(layer "F.Cu")
		(hatch none 0.5)
		(connect_pads
			(clearance 0)
		)
		(min_thickness 0.25)
		(keepout
			(tracks allowed)
			(vias allowed)
			(pads allowed)
			(copperpour allowed)
			(footprints allowed)
		)
		(placement
			(enabled no)
			(sheetname "")
		)
		(fill
			(thermal_gap 0.5)
			(thermal_bridge_width 0.5)
			(island_removal_mode 0)
		)
		(polygon
			(pts
				(xy 431.8254 -20.04822) (xy 431.8254 -16.913606) (xy 433.604162 -16.913606) (xy 433.604162 -20.04822)
			)
		)
	)
	(zone
		(layer "F.Cu")
		(hatch none 0.5)
		(connect_pads
			(clearance 0)
		)
		(min_thickness 0.25)
		(keepout
			(tracks allowed)
			(vias allowed)
			(pads allowed)
			(copperpour allowed)
			(footprints not_allowed)
		)
		(placement
			(enabled no)
			(sheetname "")
		)
		(fill
			(thermal_gap 0.5)
			(thermal_bridge_width 0.5)
			(island_removal_mode 0)
		)
		(polygon
			(pts
				(arc
					(start 458.659992 -160.50006)
					(mid 461.460088 -157.699964)
					(end 464.25993 -160.50006)
				)
				(arc
					(start 464.25993 -160.50006)
					(mid 461.460088 -163.299902)
					(end 458.659992 -160.50006)
				)
			)
		)
	)
	(zone
		(layer "F.Cu")
		(hatch none 0.5)
		(connect_pads
			(clearance 0)
		)
		(min_thickness 0.25)
		(keepout
			(tracks allowed)
			(vias allowed)
			(pads allowed)
			(copperpour allowed)
			(footprints allowed)
		)
		(placement
			(enabled no)
			(sheetname "")
		)
		(fill
			(thermal_gap 0.5)
			(thermal_bridge_width 0.5)
			(island_removal_mode 0)
		)
		(polygon
			(pts
				(xy 214.440262 -319.243202) (xy 214.440262 -316.881002) (xy 217.056462 -316.881002) (xy 217.056462 -319.243202)
			)
		)
	)
	(zone
		(layer "F.Cu")
		(hatch none 0.5)
		(connect_pads
			(clearance 0)
		)
		(min_thickness 0.25)
		(keepout
			(tracks allowed)
			(vias allowed)
			(pads allowed)
			(copperpour allowed)
			(footprints allowed)
		)
		(placement
			(enabled no)
			(sheetname "")
		)
		(fill
			(thermal_gap 0.5)
			(thermal_bridge_width 0.5)
			(island_removal_mode 0)
		)
		(polygon
			(pts
				(xy 47.522892 -404.802594) (xy 47.522892 -399.959576) (xy 49.407318 -399.959576) (xy 49.407318 -404.802594)
			)
		)
	)
	(zone
		(layer "F.Cu")
		(hatch none 0.5)
		(connect_pads
			(clearance 0)
		)
		(min_thickness 0.25)
		(keepout
			(tracks allowed)
			(vias allowed)
			(pads allowed)
			(copperpour allowed)
			(footprints allowed)
		)
		(placement
			(enabled no)
			(sheetname "")
		)
		(fill
			(thermal_gap 0.5)
			(thermal_bridge_width 0.5)
			(island_removal_mode 0)
		)
		(polygon
			(pts
				(xy 56.37911 -226.016566) (xy 56.37911 -225.572828) (xy 58.704226 -225.572828) (xy 58.704226 -226.016566)
			)
		)
	)
	(zone
		(layer "F.Cu")
		(hatch none 0.5)
		(connect_pads
			(clearance 0)
		)
		(min_thickness 0.25)
		(keepout
			(tracks not_allowed)
			(vias allowed)
			(pads allowed)
			(copperpour not_allowed)
			(footprints allowed)
		)
		(placement
			(enabled no)
			(sheetname "")
		)
		(fill
			(thermal_gap 0.5)
			(thermal_bridge_width 0.5)
			(island_removal_mode 0)
		)
		(polygon
			(pts
				(xy 416.209988 -176.957736) (xy 415.960306 -176.957736) (xy 415.960306 -179.26812) (xy 416.266122 -179.26812)
				(xy 416.266122 -179.405788) (xy 418.313362 -179.405788) (xy 418.313362 -181.259988) (xy 418.072316 -181.259988)
				(xy 418.072316 -181.502304) (xy 418.5539 -181.502304) (xy 418.5539 -177.55362) (xy 418.368988 -177.738532)
				(xy 418.368988 -179.11445) (xy 416.209988 -179.11445)
			)
		)
	)
	(zone
		(layer "F.Cu")
		(hatch none 0.5)
		(connect_pads
			(clearance 0)
		)
		(min_thickness 0.25)
		(keepout
			(tracks allowed)
			(vias allowed)
			(pads allowed)
			(copperpour allowed)
			(footprints not_allowed)
		)
		(placement
			(enabled no)
			(sheetname "")
		)
		(fill
			(thermal_gap 0.5)
			(thermal_bridge_width 0.5)
			(island_removal_mode 0)
		)
		(polygon
			(pts
				(xy 11.75004 -37.675058) (xy 11.75004 -66.324988) (xy 24.04999 -66.324988) (xy 24.04999 -37.675058)
			)
		)
	)
	(zone
		(layer "F.Cu")
		(hatch none 0.5)
		(connect_pads
			(clearance 0)
		)
		(min_thickness 0.25)
		(keepout
			(tracks allowed)
			(vias allowed)
			(pads allowed)
			(copperpour allowed)
			(footprints allowed)
		)
		(placement
			(enabled no)
			(sheetname "")
		)
		(fill
			(thermal_gap 0.5)
			(thermal_bridge_width 0.5)
			(island_removal_mode 0)
		)
		(polygon
			(pts
				(xy 370.965984 -404.802594) (xy 370.965984 -399.959576) (xy 372.85041 -399.959576) (xy 372.85041 -404.802594)
			)
		)
	)
	(zone
		(layer "F.Cu")
		(hatch none 0.5)
		(connect_pads
			(clearance 0)
		)
		(min_thickness 0.25)
		(keepout
			(tracks allowed)
			(vias allowed)
			(pads allowed)
			(copperpour allowed)
			(footprints allowed)
		)
		(placement
			(enabled no)
			(sheetname "")
		)
		(fill
			(thermal_gap 0.5)
			(thermal_bridge_width 0.5)
			(island_removal_mode 0)
		)
		(polygon
			(pts
				(xy 29.647642 -211.566506) (xy 29.647642 -211.122768) (xy 31.972758 -211.122768) (xy 31.972758 -211.566506)
			)
		)
	)
	(zone
		(layer "F.Cu")
		(hatch none 0.5)
		(connect_pads
			(clearance 0)
		)
		(min_thickness 0.25)
		(keepout
			(tracks allowed)
			(vias allowed)
			(pads allowed)
			(copperpour allowed)
			(footprints allowed)
		)
		(placement
			(enabled no)
			(sheetname "")
		)
		(fill
			(thermal_gap 0.5)
			(thermal_bridge_width 0.5)
			(island_removal_mode 0)
		)
		(polygon
			(pts
				(xy 409.831794 -196.154802) (xy 409.831794 -195.926202) (xy 411.863794 -195.926202) (xy 411.863794 -196.154802)
			)
		)
	)
	(zone
		(layer "F.Cu")
		(hatch none 0.5)
		(connect_pads
			(clearance 0)
		)
		(min_thickness 0.25)
		(keepout
			(tracks allowed)
			(vias allowed)
			(pads allowed)
			(copperpour allowed)
			(footprints allowed)
		)
		(placement
			(enabled no)
			(sheetname "")
		)
		(fill
			(thermal_gap 0.5)
			(thermal_bridge_width 0.5)
			(island_removal_mode 0)
		)
		(polygon
			(pts
				(xy 292.67531 -277.016464) (xy 292.67531 -276.572726) (xy 295.000426 -276.572726) (xy 295.000426 -277.016464)
			)
		)
	)
	(zone
		(layer "F.Cu")
		(hatch none 0.5)
		(connect_pads
			(clearance 0)
		)
		(min_thickness 0.25)
		(keepout
			(tracks allowed)
			(vias allowed)
			(pads allowed)
			(copperpour allowed)
			(footprints allowed)
		)
		(placement
			(enabled no)
			(sheetname "")
		)
		(fill
			(thermal_gap 0.5)
			(thermal_bridge_width 0.5)
			(island_removal_mode 0)
		)
		(polygon
			(pts
				(xy 29.647642 -286.366458) (xy 29.647642 -285.92272) (xy 31.972758 -285.92272) (xy 31.972758 -286.366458)
			)
		)
	)
	(zone
		(layer "F.Cu")
		(hatch none 0.5)
		(connect_pads
			(clearance 0)
		)
		(min_thickness 0.25)
		(keepout
			(tracks allowed)
			(vias allowed)
			(pads allowed)
			(copperpour allowed)
			(footprints allowed)
		)
		(placement
			(enabled no)
			(sheetname "")
		)
		(fill
			(thermal_gap 0.5)
			(thermal_bridge_width 0.5)
			(island_removal_mode 0)
		)
		(polygon
			(pts
				(xy 137.8077 -218.437968) (xy 138.09472 -218.437968) (xy 138.1252 -218.407488) (xy 138.1252 -217.780108)
				(xy 138.03884 -217.693748) (xy 137.85088 -217.693748) (xy 137.77722 -217.767408) (xy 137.77722 -218.407488)
			)
		)
	)
	(zone
		(layer "F.Cu")
		(hatch none 0.5)
		(connect_pads
			(clearance 0)
		)
		(min_thickness 0.25)
		(keepout
			(tracks allowed)
			(vias allowed)
			(pads allowed)
			(copperpour allowed)
			(footprints allowed)
		)
		(placement
			(enabled no)
			(sheetname "")
		)
		(fill
			(thermal_gap 0.5)
			(thermal_bridge_width 0.5)
			(island_removal_mode 0)
		)
		(polygon
			(pts
				(xy 31.972758 -237.066582) (xy 29.647642 -237.066582) (xy 29.50464 -237.066582) (xy 29.50464 -235.873036)
				(xy 32.025336 -235.873036) (xy 32.025336 -237.066582)
			)
		)
	)
	(zone
		(layer "F.Cu")
		(hatch none 0.5)
		(connect_pads
			(clearance 0)
		)
		(min_thickness 0.25)
		(keepout
			(tracks allowed)
			(vias allowed)
			(pads allowed)
			(copperpour allowed)
			(footprints allowed)
		)
		(placement
			(enabled no)
			(sheetname "")
		)
		(fill
			(thermal_gap 0.5)
			(thermal_bridge_width 0.5)
			(island_removal_mode 0)
		)
		(polygon
			(pts
				(xy 440.006994 -235.026454) (xy 442.038994 -235.026454) (xy 442.038994 -235.02874) (xy 442.21781 -235.02874)
				(xy 442.21781 -235.265976) (xy 442.355732 -235.265976) (xy 442.398912 -235.309156) (xy 442.398912 -235.441998)
				(xy 442.398912 -235.746036) (xy 442.326268 -235.81868) (xy 439.786014 -235.81868) (xy 439.64479 -235.677456)
				(xy 439.64479 -235.480352) (xy 439.726324 -235.398818) (xy 439.726324 -235.026454) (xy 439.82386 -235.026454)
				(xy 439.87085 -235.026454)
			)
		)
	)
	(zone
		(layer "F.Cu")
		(hatch none 0.5)
		(connect_pads
			(clearance 0)
		)
		(min_thickness 0.25)
		(keepout
			(tracks allowed)
			(vias allowed)
			(pads allowed)
			(copperpour allowed)
			(footprints allowed)
		)
		(placement
			(enabled no)
			(sheetname "")
		)
		(fill
			(thermal_gap 0.5)
			(thermal_bridge_width 0.5)
			(island_removal_mode 0)
		)
		(polygon
			(pts
				(xy 210.598258 -236.104938) (xy 210.598258 -235.876338) (xy 212.630258 -235.876338) (xy 212.630258 -236.104938)
			)
		)
	)
	(zone
		(layer "F.Cu")
		(hatch none 0.5)
		(connect_pads
			(clearance 0)
		)
		(min_thickness 0.25)
		(keepout
			(tracks allowed)
			(vias allowed)
			(pads allowed)
			(copperpour allowed)
			(footprints allowed)
		)
		(placement
			(enabled no)
			(sheetname "")
		)
		(fill
			(thermal_gap 0.5)
			(thermal_bridge_width 0.5)
			(island_removal_mode 0)
		)
		(polygon
			(pts
				(xy 455.094594 -205.27645) (xy 457.126594 -205.27645) (xy 457.126594 -205.50505) (xy 455.094594 -205.50505)
				(xy 454.95845 -205.50505) (xy 454.91146 -205.50505) (xy 454.91146 -205.27645) (xy 454.95845 -205.27645)
			)
		)
	)
	(zone
		(layer "F.Cu")
		(hatch none 0.5)
		(connect_pads
			(clearance 0)
		)
		(min_thickness 0.25)
		(keepout
			(tracks allowed)
			(vias allowed)
			(pads allowed)
			(copperpour allowed)
			(footprints allowed)
		)
		(placement
			(enabled no)
			(sheetname "")
		)
		(fill
			(thermal_gap 0.5)
			(thermal_bridge_width 0.5)
			(island_removal_mode 0)
		)
		(polygon
			(pts
				(xy 307.76291 -308.46649) (xy 307.76291 -308.022752) (xy 310.088026 -308.022752) (xy 310.088026 -308.46649)
			)
		)
	)
	(zone
		(layer "F.Cu")
		(hatch none 0.5)
		(connect_pads
			(clearance 0)
		)
		(min_thickness 0.25)
		(keepout
			(tracks not_allowed)
			(vias allowed)
			(pads allowed)
			(copperpour not_allowed)
			(footprints allowed)
		)
		(placement
			(enabled no)
			(sheetname "")
		)
		(fill
			(thermal_gap 0.5)
			(thermal_bridge_width 0.5)
			(island_removal_mode 0)
		)
		(polygon
			(pts
				(arc
					(start 227.65004 -44.500038)
					(mid 228.650038 -43.50004)
					(end 229.650036 -44.500038)
				)
				(arc
					(start 229.650036 -44.500038)
					(mid 228.650038 -45.500036)
					(end 227.65004 -44.500038)
				)
			)
		)
	)
	(zone
		(layer "F.Cu")
		(hatch none 0.5)
		(connect_pads
			(clearance 0)
		)
		(min_thickness 0.25)
		(keepout
			(tracks allowed)
			(vias allowed)
			(pads allowed)
			(copperpour allowed)
			(footprints allowed)
		)
		(placement
			(enabled no)
			(sheetname "")
		)
		(fill
			(thermal_gap 0.5)
			(thermal_bridge_width 0.5)
			(island_removal_mode 0)
		)
		(polygon
			(pts
				(xy 87.95258 -336.318606) (xy 86.13648 -336.318606) (xy 86.13648 -334.939386) (xy 87.95258 -334.939386)
			)
		)
	)
	(zone
		(layer "F.Cu")
		(hatch none 0.5)
		(connect_pads
			(clearance 0)
		)
		(min_thickness 0.25)
		(keepout
			(tracks allowed)
			(vias allowed)
			(pads allowed)
			(copperpour allowed)
			(footprints allowed)
		)
		(placement
			(enabled no)
			(sheetname "")
		)
		(fill
			(thermal_gap 0.5)
			(thermal_bridge_width 0.5)
			(island_removal_mode 0)
		)
		(polygon
			(pts
				(xy 122.761248 -404.802594) (xy 122.761248 -399.959576) (xy 124.645674 -399.959576) (xy 124.645674 -404.802594)
			)
		)
	)
	(zone
		(layer "F.Cu")
		(hatch none 0.5)
		(connect_pads
			(clearance 0)
		)
		(min_thickness 0.25)
		(keepout
			(tracks allowed)
			(vias allowed)
			(pads allowed)
			(copperpour allowed)
			(footprints allowed)
		)
		(placement
			(enabled no)
			(sheetname "")
		)
		(fill
			(thermal_gap 0.5)
			(thermal_bridge_width 0.5)
			(island_removal_mode 0)
		)
		(polygon
			(pts
				(xy 157.791658 -248.854976) (xy 157.791658 -248.626376) (xy 159.823658 -248.626376) (xy 159.823658 -248.854976)
			)
		)
	)
	(zone
		(layer "F.Cu")
		(hatch none 0.5)
		(connect_pads
			(clearance 0)
		)
		(min_thickness 0.25)
		(keepout
			(tracks allowed)
			(vias allowed)
			(pads allowed)
			(copperpour allowed)
			(footprints allowed)
		)
		(placement
			(enabled no)
			(sheetname "")
		)
		(fill
			(thermal_gap 0.5)
			(thermal_bridge_width 0.5)
			(island_removal_mode 0)
		)
		(polygon
			(pts
				(xy 44.735242 -248.966482) (xy 44.735242 -248.522744) (xy 47.060358 -248.522744) (xy 47.060358 -248.966482)
			)
		)
	)
	(zone
		(layer "F.Cu")
		(hatch none 0.5)
		(connect_pads
			(clearance 0)
		)
		(min_thickness 0.25)
		(keepout
			(tracks allowed)
			(vias allowed)
			(pads allowed)
			(copperpour allowed)
			(footprints allowed)
		)
		(placement
			(enabled no)
			(sheetname "")
		)
		(fill
			(thermal_gap 0.5)
			(thermal_bridge_width 0.5)
			(island_removal_mode 0)
		)
		(polygon
			(pts
				(xy 14.560042 -290.61664) (xy 14.560042 -290.172902) (xy 16.885158 -290.172902) (xy 16.885158 -290.61664)
			)
		)
	)
	(zone
		(layer "F.Cu")
		(hatch none 0.5)
		(connect_pads
			(clearance 0)
		)
		(min_thickness 0.25)
		(keepout
			(tracks allowed)
			(vias allowed)
			(pads allowed)
			(copperpour allowed)
			(footprints allowed)
		)
		(placement
			(enabled no)
			(sheetname "")
		)
		(fill
			(thermal_gap 0.5)
			(thermal_bridge_width 0.5)
			(island_removal_mode 0)
		)
		(polygon
			(pts
				(xy 157.791658 -273.504914) (xy 157.791658 -273.276314) (xy 159.823658 -273.276314) (xy 159.823658 -273.504914)
			)
		)
	)
	(zone
		(layer "F.Cu")
		(hatch none 0.5)
		(connect_pads
			(clearance 0)
		)
		(min_thickness 0.25)
		(keepout
			(tracks allowed)
			(vias allowed)
			(pads allowed)
			(copperpour allowed)
			(footprints allowed)
		)
		(placement
			(enabled no)
			(sheetname "")
		)
		(fill
			(thermal_gap 0.5)
			(thermal_bridge_width 0.5)
			(island_removal_mode 0)
		)
		(polygon
			(pts
				(xy 277.58771 -199.666606) (xy 277.58771 -199.222868) (xy 279.912826 -199.222868) (xy 279.912826 -199.666606)
			)
		)
	)
	(zone
		(layer "F.Cu")
		(hatch none 0.5)
		(connect_pads
			(clearance 0)
		)
		(min_thickness 0.25)
		(keepout
			(tracks allowed)
			(vias allowed)
			(pads allowed)
			(copperpour allowed)
			(footprints allowed)
		)
		(placement
			(enabled no)
			(sheetname "")
		)
		(fill
			(thermal_gap 0.5)
			(thermal_bridge_width 0.5)
			(island_removal_mode 0)
		)
		(polygon
			(pts
				(xy 11.11631 -312.716418) (xy 11.11631 -312.27268) (xy 13.441426 -312.27268) (xy 13.441426 -312.716418)
			)
		)
	)
	(zone
		(layer "F.Cu")
		(hatch none 0.5)
		(connect_pads
			(clearance 0)
		)
		(min_thickness 0.25)
		(keepout
			(tracks allowed)
			(vias allowed)
			(pads allowed)
			(copperpour allowed)
			(footprints allowed)
		)
		(placement
			(enabled no)
			(sheetname "")
		)
		(fill
			(thermal_gap 0.5)
			(thermal_bridge_width 0.5)
			(island_removal_mode 0)
		)
		(polygon
			(pts
				(xy 455.094594 -240.976404) (xy 457.126594 -240.976404) (xy 457.126594 -241.205004) (xy 455.094594 -241.205004)
				(xy 454.95845 -241.205004) (xy 454.91146 -241.205004) (xy 454.91146 -240.976404) (xy 454.95845 -240.976404)
			)
		)
	)
	(zone
		(layer "F.Cu")
		(hatch none 0.5)
		(connect_pads
			(clearance 0)
		)
		(min_thickness 0.25)
		(keepout
			(tracks allowed)
			(vias allowed)
			(pads allowed)
			(copperpour allowed)
			(footprints allowed)
		)
		(placement
			(enabled no)
			(sheetname "")
		)
		(fill
			(thermal_gap 0.5)
			(thermal_bridge_width 0.5)
			(island_removal_mode 0)
		)
		(polygon
			(pts
				(xy 414.542224 -5.888228) (xy 414.542224 -3.952748) (xy 416.713924 -3.952748) (xy 416.713924 -5.888228)
			)
		)
	)
	(zone
		(layer "F.Cu")
		(hatch none 0.5)
		(connect_pads
			(clearance 0)
		)
		(min_thickness 0.25)
		(keepout
			(tracks allowed)
			(vias allowed)
			(pads allowed)
			(copperpour allowed)
			(footprints allowed)
		)
		(placement
			(enabled no)
			(sheetname "")
		)
		(fill
			(thermal_gap 0.5)
			(thermal_bridge_width 0.5)
			(island_removal_mode 0)
		)
		(polygon
			(pts
				(xy 304.319178 -203.916534) (xy 304.319178 -203.472796) (xy 306.644294 -203.472796) (xy 306.644294 -203.916534)
			)
		)
	)
	(zone
		(layer "F.Cu")
		(hatch none 0.5)
		(connect_pads
			(clearance 0)
		)
		(min_thickness 0.25)
		(keepout
			(tracks allowed)
			(vias allowed)
			(pads allowed)
			(copperpour allowed)
			(footprints allowed)
		)
		(placement
			(enabled no)
			(sheetname "")
		)
		(fill
			(thermal_gap 0.5)
			(thermal_bridge_width 0.5)
			(island_removal_mode 0)
		)
		(polygon
			(pts
				(xy 262.50011 -196.266562) (xy 262.50011 -195.822824) (xy 264.825226 -195.822824) (xy 264.825226 -196.266562)
			)
		)
	)
	(zone
		(layer "F.Cu")
		(hatch none 0.5)
		(connect_pads
			(clearance 0)
		)
		(min_thickness 0.25)
		(keepout
			(tracks allowed)
			(vias allowed)
			(pads allowed)
			(copperpour allowed)
			(footprints allowed)
		)
		(placement
			(enabled no)
			(sheetname "")
		)
		(fill
			(thermal_gap 0.5)
			(thermal_bridge_width 0.5)
			(island_removal_mode 0)
		)
		(polygon
			(pts
				(xy 262.50011 -264.266426) (xy 262.50011 -263.822688) (xy 264.825226 -263.822688) (xy 264.825226 -264.266426)
			)
		)
	)
	(zone
		(layer "F.Cu")
		(hatch none 0.5)
		(connect_pads
			(clearance 0)
		)
		(min_thickness 0.25)
		(keepout
			(tracks allowed)
			(vias allowed)
			(pads allowed)
			(copperpour allowed)
			(footprints allowed)
		)
		(placement
			(enabled no)
			(sheetname "")
		)
		(fill
			(thermal_gap 0.5)
			(thermal_bridge_width 0.5)
			(island_removal_mode 0)
		)
		(polygon
			(pts
				(xy 259.056378 -220.9165) (xy 259.056378 -220.472762) (xy 261.381494 -220.472762) (xy 261.381494 -220.9165)
			)
		)
	)
	(zone
		(layer "F.Cu")
		(hatch none 0.5)
		(connect_pads
			(clearance 0)
		)
		(min_thickness 0.25)
		(keepout
			(tracks allowed)
			(vias allowed)
			(pads allowed)
			(copperpour allowed)
			(footprints allowed)
		)
		(placement
			(enabled no)
			(sheetname "")
		)
		(fill
			(thermal_gap 0.5)
			(thermal_bridge_width 0.5)
			(island_removal_mode 0)
		)
		(polygon
			(pts
				(xy 44.735242 -237.066582) (xy 44.735242 -236.622844) (xy 47.060358 -236.622844) (xy 47.060358 -237.066582)
			)
		)
	)
	(zone
		(layer "F.Cu")
		(hatch none 0.5)
		(connect_pads
			(clearance 0)
		)
		(min_thickness 0.25)
		(keepout
			(tracks allowed)
			(vias allowed)
			(pads allowed)
			(copperpour allowed)
			(footprints not_allowed)
		)
		(placement
			(enabled no)
			(sheetname "")
		)
		(fill
			(thermal_gap 0.5)
			(thermal_bridge_width 0.5)
			(island_removal_mode 0)
		)
		(polygon
			(pts
				(arc
					(start 380.458726 -354.434902)
					(mid 384.458972 -350.434656)
					(end 388.458964 -354.434902)
				)
				(arc
					(start 388.458964 -354.434902)
					(mid 384.458972 -358.434894)
					(end 380.458726 -354.434902)
				)
			)
		)
	)
	(zone
		(layer "F.Cu")
		(hatch none 0.5)
		(connect_pads
			(clearance 0)
		)
		(min_thickness 0.25)
		(keepout
			(tracks allowed)
			(vias allowed)
			(pads allowed)
			(copperpour allowed)
			(footprints allowed)
		)
		(placement
			(enabled no)
			(sheetname "")
		)
		(fill
			(thermal_gap 0.5)
			(thermal_bridge_width 0.5)
			(island_removal_mode 0)
		)
		(polygon
			(pts
				(xy 26.20391 -220.066616) (xy 26.20391 -219.622878) (xy 28.529026 -219.622878) (xy 28.529026 -220.066616)
			)
		)
	)
	(zone
		(layer "F.Cu")
		(hatch none 0.5)
		(connect_pads
			(clearance 0)
		)
		(min_thickness 0.25)
		(keepout
			(tracks allowed)
			(vias allowed)
			(pads allowed)
			(copperpour allowed)
			(footprints allowed)
		)
		(placement
			(enabled no)
			(sheetname "")
		)
		(fill
			(thermal_gap 0.5)
			(thermal_bridge_width 0.5)
			(island_removal_mode 0)
		)
		(polygon
			(pts
				(xy 59.775852 -404.802594) (xy 59.775852 -399.959576) (xy 61.660278 -399.959576) (xy 61.660278 -404.802594)
			)
		)
	)
	(zone
		(layer "F.Cu")
		(hatch none 0.5)
		(connect_pads
			(clearance 0)
		)
		(min_thickness 0.25)
		(keepout
			(tracks allowed)
			(vias allowed)
			(pads allowed)
			(copperpour allowed)
			(footprints allowed)
		)
		(placement
			(enabled no)
			(sheetname "")
		)
		(fill
			(thermal_gap 0.5)
			(thermal_bridge_width 0.5)
			(island_removal_mode 0)
		)
		(polygon
			(pts
				(xy 405.731726 -282.005024) (xy 405.731726 -281.776424) (xy 407.763726 -281.776424) (xy 407.763726 -282.005024)
			)
		)
	)
	(zone
		(layer "F.Cu")
		(hatch none 0.5)
		(connect_pads
			(clearance 0)
		)
		(min_thickness 0.25)
		(keepout
			(tracks allowed)
			(vias allowed)
			(pads allowed)
			(copperpour allowed)
			(footprints allowed)
		)
		(placement
			(enabled no)
			(sheetname "")
		)
		(fill
			(thermal_gap 0.5)
			(thermal_bridge_width 0.5)
			(island_removal_mode 0)
		)
		(polygon
			(pts
				(xy 180.423058 -262.454898) (xy 180.423058 -262.226298) (xy 182.455058 -262.226298) (xy 182.455058 -262.454898)
			)
		)
	)
	(zone
		(layer "F.Cu")
		(hatch none 0.5)
		(connect_pads
			(clearance 0)
		)
		(min_thickness 0.25)
		(keepout
			(tracks allowed)
			(vias allowed)
			(pads allowed)
			(copperpour allowed)
			(footprints allowed)
		)
		(placement
			(enabled no)
			(sheetname "")
		)
		(fill
			(thermal_gap 0.5)
			(thermal_bridge_width 0.5)
			(island_removal_mode 0)
		)
		(polygon
			(pts
				(xy 428.363126 -236.954822) (xy 428.363126 -236.726222) (xy 430.395126 -236.726222) (xy 430.395126 -236.954822)
			)
		)
	)
	(zone
		(layer "F.Cu")
		(hatch none 0.5)
		(connect_pads
			(clearance 0)
		)
		(min_thickness 0.25)
		(keepout
			(tracks allowed)
			(vias allowed)
			(pads allowed)
			(copperpour allowed)
			(footprints allowed)
		)
		(placement
			(enabled no)
			(sheetname "")
		)
		(fill
			(thermal_gap 0.5)
			(thermal_bridge_width 0.5)
			(island_removal_mode 0)
		)
		(polygon
			(pts
				(xy 274.143978 -216.666572) (xy 274.143978 -216.222834) (xy 276.469094 -216.222834) (xy 276.469094 -216.666572)
			)
		)
	)
	(zone
		(layer "F.Cu")
		(hatch none 0.5)
		(connect_pads
			(clearance 0)
		)
		(min_thickness 0.25)
		(keepout
			(tracks allowed)
			(vias allowed)
			(pads allowed)
			(copperpour allowed)
			(footprints allowed)
		)
		(placement
			(enabled no)
			(sheetname "")
		)
		(fill
			(thermal_gap 0.5)
			(thermal_bridge_width 0.5)
			(island_removal_mode 0)
		)
		(polygon
			(pts
				(xy 44.735242 -225.166428) (xy 44.735242 -224.72269) (xy 47.060358 -224.72269) (xy 47.060358 -225.166428)
			)
		)
	)
	(zone
		(layer "F.Cu")
		(hatch none 0.5)
		(connect_pads
			(clearance 0)
		)
		(min_thickness 0.25)
		(keepout
			(tracks allowed)
			(vias allowed)
			(pads allowed)
			(copperpour allowed)
			(footprints allowed)
		)
		(placement
			(enabled no)
			(sheetname "")
		)
		(fill
			(thermal_gap 0.5)
			(thermal_bridge_width 0.5)
			(island_removal_mode 0)
		)
		(polygon
			(pts
				(xy 458.538326 -214.85479) (xy 458.538326 -214.62619) (xy 460.570326 -214.62619) (xy 460.570326 -214.85479)
			)
		)
	)
	(zone
		(layer "F.Cu")
		(hatch none 0.5)
		(connect_pads
			(clearance 0)
		)
		(min_thickness 0.25)
		(keepout
			(tracks allowed)
			(vias allowed)
			(pads allowed)
			(copperpour allowed)
			(footprints allowed)
		)
		(placement
			(enabled no)
			(sheetname "")
		)
		(fill
			(thermal_gap 0.5)
			(thermal_bridge_width 0.5)
			(island_removal_mode 0)
		)
		(polygon
			(pts
				(xy 37.59454 -395.2367) (xy 37.59454 -389.91286) (xy 42.6212 -389.91286) (xy 42.6212 -395.2367)
			)
		)
	)
	(zone
		(layer "F.Cu")
		(hatch none 0.5)
		(connect_pads
			(clearance 0)
		)
		(min_thickness 0.25)
		(keepout
			(tracks allowed)
			(vias allowed)
			(pads allowed)
			(copperpour allowed)
			(footprints allowed)
		)
		(placement
			(enabled no)
			(sheetname "")
		)
		(fill
			(thermal_gap 0.5)
			(thermal_bridge_width 0.5)
			(island_removal_mode 0)
		)
		(polygon
			(pts
				(xy 304.319178 -229.41661) (xy 304.319178 -228.972872) (xy 306.644294 -228.972872) (xy 306.644294 -229.41661)
			)
		)
	)
	(zone
		(layer "F.Cu")
		(hatch none 0.5)
		(connect_pads
			(clearance 0)
		)
		(min_thickness 0.25)
		(keepout
			(tracks allowed)
			(vias allowed)
			(pads allowed)
			(copperpour allowed)
			(footprints allowed)
		)
		(placement
			(enabled no)
			(sheetname "")
		)
		(fill
			(thermal_gap 0.5)
			(thermal_bridge_width 0.5)
			(island_removal_mode 0)
		)
		(polygon
			(pts
				(xy 428.363126 -198.704962) (xy 428.363126 -198.476362) (xy 430.395126 -198.476362) (xy 430.395126 -198.704962)
			)
		)
	)
	(zone
		(layer "F.Cu")
		(hatch none 0.5)
		(connect_pads
			(clearance 0)
		)
		(min_thickness 0.25)
		(keepout
			(tracks allowed)
			(vias allowed)
			(pads allowed)
			(copperpour allowed)
			(footprints allowed)
		)
		(placement
			(enabled no)
			(sheetname "")
		)
		(fill
			(thermal_gap 0.5)
			(thermal_bridge_width 0.5)
			(island_removal_mode 0)
		)
		(polygon
			(pts
				(xy 180.423058 -208.054956) (xy 180.423058 -207.826356) (xy 182.455058 -207.826356) (xy 182.455058 -208.054956)
			)
		)
	)
	(zone
		(layer "F.Cu")
		(hatch none 0.5)
		(connect_pads
			(clearance 0)
		)
		(min_thickness 0.25)
		(keepout
			(tracks allowed)
			(vias allowed)
			(pads allowed)
			(copperpour allowed)
			(footprints allowed)
		)
		(placement
			(enabled no)
			(sheetname "")
		)
		(fill
			(thermal_gap 0.5)
			(thermal_bridge_width 0.5)
			(island_removal_mode 0)
		)
		(polygon
			(pts
				(xy 63.977012 -221.766638) (xy 63.977012 -221.3229) (xy 66.212212 -221.3229) (xy 66.24701 -221.3229)
				(xy 66.24701 -221.766638) (xy 66.212212 -221.766638)
			)
		)
	)
	(zone
		(layer "F.Cu")
		(hatch none 0.5)
		(connect_pads
			(clearance 0)
		)
		(min_thickness 0.25)
		(keepout
			(tracks allowed)
			(vias allowed)
			(pads allowed)
			(copperpour allowed)
			(footprints allowed)
		)
		(placement
			(enabled no)
			(sheetname "")
		)
		(fill
			(thermal_gap 0.5)
			(thermal_bridge_width 0.5)
			(island_removal_mode 0)
		)
		(polygon
			(pts
				(xy 455.094594 -219.726256) (xy 457.126594 -219.726256) (xy 457.126594 -219.954856) (xy 455.094594 -219.954856)
				(xy 454.963276 -219.954856) (xy 454.937368 -219.954856) (xy 454.937368 -219.726256) (xy 454.963276 -219.726256)
			)
		)
	)
	(zone
		(layer "F.Cu")
		(hatch none 0.5)
		(connect_pads
			(clearance 0)
		)
		(min_thickness 0.25)
		(keepout
			(tracks allowed)
			(vias allowed)
			(pads allowed)
			(copperpour allowed)
			(footprints allowed)
		)
		(placement
			(enabled no)
			(sheetname "")
		)
		(fill
			(thermal_gap 0.5)
			(thermal_bridge_width 0.5)
			(island_removal_mode 0)
		)
		(polygon
			(pts
				(xy 307.76291 -266.816586) (xy 307.76291 -266.372848) (xy 310.088026 -266.372848) (xy 310.088026 -266.816586)
			)
		)
	)
	(zone
		(layer "F.Cu")
		(hatch none 0.5)
		(connect_pads
			(clearance 0)
		)
		(min_thickness 0.25)
		(keepout
			(tracks allowed)
			(vias allowed)
			(pads allowed)
			(copperpour allowed)
			(footprints allowed)
		)
		(placement
			(enabled no)
			(sheetname "")
		)
		(fill
			(thermal_gap 0.5)
			(thermal_bridge_width 0.5)
			(island_removal_mode 0)
		)
		(polygon
			(pts
				(xy 440.006994 -233.326432) (xy 442.038994 -233.326432) (xy 442.038994 -233.328718) (xy 442.21781 -233.328718)
				(xy 442.21781 -233.565954) (xy 442.355732 -233.565954) (xy 442.398912 -233.609134) (xy 442.398912 -233.741976)
				(xy 442.398912 -234.046014) (xy 442.326268 -234.118658) (xy 439.786014 -234.118658) (xy 439.64479 -233.977434)
				(xy 439.64479 -233.78033) (xy 439.726324 -233.698796) (xy 439.726324 -233.326432) (xy 439.82386 -233.326432)
				(xy 439.87085 -233.326432)
			)
		)
	)
	(zone
		(layer "F.Cu")
		(hatch none 0.5)
		(connect_pads
			(clearance 0)
		)
		(min_thickness 0.25)
		(keepout
			(tracks allowed)
			(vias allowed)
			(pads allowed)
			(copperpour allowed)
			(footprints allowed)
		)
		(placement
			(enabled no)
			(sheetname "")
		)
		(fill
			(thermal_gap 0.5)
			(thermal_bridge_width 0.5)
			(island_removal_mode 0)
		)
		(polygon
			(pts
				(xy 210.598258 -316.004956) (xy 210.598258 -315.776356) (xy 212.630258 -315.776356) (xy 212.630258 -316.004956)
			)
		)
	)
	(zone
		(layer "F.Cu")
		(hatch none 0.5)
		(connect_pads
			(clearance 0)
		)
		(min_thickness 0.25)
		(keepout
			(tracks allowed)
			(vias allowed)
			(pads allowed)
			(copperpour allowed)
			(footprints allowed)
		)
		(placement
			(enabled no)
			(sheetname "")
		)
		(fill
			(thermal_gap 0.5)
			(thermal_bridge_width 0.5)
			(island_removal_mode 0)
		)
		(polygon
			(pts
				(xy 165.335458 -277.526496) (xy 167.367458 -277.526496) (xy 167.367458 -277.528782) (xy 167.546274 -277.528782)
				(xy 167.546274 -277.766018) (xy 167.684196 -277.766018) (xy 167.727376 -277.809198) (xy 167.727376 -277.94204)
				(xy 167.727376 -278.246078) (xy 167.654732 -278.318722) (xy 165.114478 -278.318722) (xy 164.973254 -278.177498)
				(xy 164.973254 -277.980394) (xy 165.054788 -277.89886) (xy 165.054788 -277.526496) (xy 165.152324 -277.526496)
				(xy 165.199314 -277.526496)
			)
		)
	)
	(zone
		(layer "F.Cu")
		(hatch none 0.5)
		(connect_pads
			(clearance 0)
		)
		(min_thickness 0.25)
		(keepout
			(tracks allowed)
			(vias allowed)
			(pads allowed)
			(copperpour allowed)
			(footprints allowed)
		)
		(placement
			(enabled no)
			(sheetname "")
		)
		(fill
			(thermal_gap 0.5)
			(thermal_bridge_width 0.5)
			(island_removal_mode 0)
		)
		(polygon
			(pts
				(xy 161.891726 -207.204818) (xy 161.891726 -206.976218) (xy 163.923726 -206.976218) (xy 163.923726 -207.204818)
			)
		)
	)
	(zone
		(layer "F.Cu")
		(hatch none 0.5)
		(connect_pads
			(clearance 0)
		)
		(min_thickness 0.25)
		(keepout
			(tracks not_allowed)
			(vias allowed)
			(pads allowed)
			(copperpour not_allowed)
			(footprints allowed)
		)
		(placement
			(enabled no)
			(sheetname "")
		)
		(fill
			(thermal_gap 0.5)
			(thermal_bridge_width 0.5)
			(island_removal_mode 0)
		)
		(polygon
			(pts
				(arc
					(start 327.899776 -160.50006)
					(mid 322.899786 -165.50005)
					(end 317.899796 -160.50006)
				)
				(arc
					(start 317.899796 -160.50006)
					(mid 322.899786 -155.50007)
					(end 327.899776 -160.50006)
				)
			)
		)
	)
	(zone
		(layer "F.Cu")
		(hatch none 0.5)
		(connect_pads
			(clearance 0)
		)
		(min_thickness 0.25)
		(keepout
			(tracks allowed)
			(vias allowed)
			(pads allowed)
			(copperpour allowed)
			(footprints allowed)
		)
		(placement
			(enabled no)
			(sheetname "")
		)
		(fill
			(thermal_gap 0.5)
			(thermal_bridge_width 0.5)
			(island_removal_mode 0)
		)
		(polygon
			(pts
				(xy 277.58771 -277.422864) (xy 279.912826 -277.422864) (xy 279.984708 -277.422864) (xy 279.984708 -278.338788)
				(xy 277.456138 -278.338788) (xy 277.456138 -277.422864)
			)
		)
	)
	(zone
		(layer "F.Cu")
		(hatch none 0.5)
		(connect_pads
			(clearance 0)
		)
		(min_thickness 0.25)
		(keepout
			(tracks allowed)
			(vias allowed)
			(pads allowed)
			(copperpour allowed)
			(footprints allowed)
		)
		(placement
			(enabled no)
			(sheetname "")
		)
		(fill
			(thermal_gap 0.5)
			(thermal_bridge_width 0.5)
			(island_removal_mode 0)
		)
		(polygon
			(pts
				(xy 31.972758 -274.466558) (xy 29.647642 -274.466558) (xy 29.516324 -274.466558) (xy 29.516324 -273.260566)
				(xy 32.025082 -273.260566) (xy 32.025082 -274.466558)
			)
		)
	)
	(zone
		(layer "F.Cu")
		(hatch none 0.5)
		(connect_pads
			(clearance 0)
		)
		(min_thickness 0.25)
		(keepout
			(tracks allowed)
			(vias allowed)
			(pads allowed)
			(copperpour allowed)
			(footprints allowed)
		)
		(placement
			(enabled no)
			(sheetname "")
		)
		(fill
			(thermal_gap 0.5)
			(thermal_bridge_width 0.5)
			(island_removal_mode 0)
		)
		(polygon
			(pts
				(xy 195.510658 -262.454898) (xy 195.510658 -262.226298) (xy 197.542658 -262.226298) (xy 197.542658 -262.454898)
			)
		)
	)
	(zone
		(layer "F.Cu")
		(hatch none 0.5)
		(connect_pads
			(clearance 0)
		)
		(min_thickness 0.25)
		(keepout
			(tracks allowed)
			(vias allowed)
			(pads allowed)
			(copperpour allowed)
			(footprints allowed)
		)
		(placement
			(enabled no)
			(sheetname "")
		)
		(fill
			(thermal_gap 0.5)
			(thermal_bridge_width 0.5)
			(island_removal_mode 0)
		)
		(polygon
			(pts
				(xy 31.62046 -171.021248) (xy 31.62046 -168.768268) (xy 32.60852 -168.768268) (xy 32.60852 -171.021248)
			)
		)
	)
	(zone
		(layer "F.Cu")
		(hatch none 0.5)
		(connect_pads
			(clearance 0)
		)
		(min_thickness 0.25)
		(keepout
			(tracks allowed)
			(vias allowed)
			(pads allowed)
			(copperpour allowed)
			(footprints allowed)
		)
		(placement
			(enabled no)
			(sheetname "")
		)
		(fill
			(thermal_gap 0.5)
			(thermal_bridge_width 0.5)
			(island_removal_mode 0)
		)
		(polygon
			(pts
				(xy 443.450726 -306.654962) (xy 443.450726 -306.426362) (xy 445.482726 -306.426362) (xy 445.482726 -306.654962)
			)
		)
	)
	(zone
		(layer "F.Cu")
		(hatch none 0.5)
		(connect_pads
			(clearance 0)
		)
		(min_thickness 0.25)
		(keepout
			(tracks allowed)
			(vias allowed)
			(pads allowed)
			(copperpour allowed)
			(footprints allowed)
		)
		(placement
			(enabled no)
			(sheetname "")
		)
		(fill
			(thermal_gap 0.5)
			(thermal_bridge_width 0.5)
			(island_removal_mode 0)
		)
		(polygon
			(pts
				(xy 409.831794 -200.404984) (xy 409.831794 -200.176384) (xy 411.863794 -200.176384) (xy 411.863794 -200.404984)
			)
		)
	)
	(zone
		(layer "F.Cu")
		(hatch none 0.5)
		(connect_pads
			(clearance 0)
		)
		(min_thickness 0.25)
		(keepout
			(tracks allowed)
			(vias allowed)
			(pads allowed)
			(copperpour allowed)
			(footprints allowed)
		)
		(placement
			(enabled no)
			(sheetname "")
		)
		(fill
			(thermal_gap 0.5)
			(thermal_bridge_width 0.5)
			(island_removal_mode 0)
		)
		(polygon
			(pts
				(xy 292.67531 -217.516456) (xy 292.67531 -217.072718) (xy 295.000426 -217.072718) (xy 295.000426 -217.516456)
			)
		)
	)
	(zone
		(layer "F.Cu")
		(hatch none 0.5)
		(connect_pads
			(clearance 0)
		)
		(min_thickness 0.25)
		(keepout
			(tracks allowed)
			(vias allowed)
			(pads allowed)
			(copperpour allowed)
			(footprints allowed)
		)
		(placement
			(enabled no)
			(sheetname "")
		)
		(fill
			(thermal_gap 0.5)
			(thermal_bridge_width 0.5)
			(island_removal_mode 0)
		)
		(polygon
			(pts
				(xy 259.056378 -265.966448) (xy 259.056378 -265.52271) (xy 261.381494 -265.52271) (xy 261.381494 -265.966448)
			)
		)
	)
	(zone
		(layer "F.Cu")
		(hatch none 0.5)
		(connect_pads
			(clearance 0)
		)
		(min_thickness 0.25)
		(keepout
			(tracks allowed)
			(vias allowed)
			(pads allowed)
			(copperpour allowed)
			(footprints allowed)
		)
		(placement
			(enabled no)
			(sheetname "")
		)
		(fill
			(thermal_gap 0.5)
			(thermal_bridge_width 0.5)
			(island_removal_mode 0)
		)
		(polygon
			(pts
				(xy 458.538326 -270.955008) (xy 458.538326 -270.726408) (xy 460.570326 -270.726408) (xy 460.570326 -270.955008)
			)
		)
	)
	(zone
		(layer "F.Cu")
		(hatch none 0.5)
		(connect_pads
			(clearance 0)
		)
		(min_thickness 0.25)
		(keepout
			(tracks allowed)
			(vias allowed)
			(pads allowed)
			(copperpour allowed)
			(footprints allowed)
		)
		(placement
			(enabled no)
			(sheetname "")
		)
		(fill
			(thermal_gap 0.5)
			(thermal_bridge_width 0.5)
			(island_removal_mode 0)
		)
		(polygon
			(pts
				(xy 261.82574 -70.957948) (xy 261.82574 -69.576188) (xy 265.09726 -69.576188) (xy 265.09726 -70.957948)
			)
		)
	)
	(zone
		(layer "F.Cu")
		(hatch none 0.5)
		(connect_pads
			(clearance 0)
		)
		(min_thickness 0.25)
		(keepout
			(tracks not_allowed)
			(vias allowed)
			(pads allowed)
			(copperpour not_allowed)
			(footprints allowed)
		)
		(placement
			(enabled no)
			(sheetname "")
		)
		(fill
			(thermal_gap 0.5)
			(thermal_bridge_width 0.5)
			(island_removal_mode 0)
		)
		(polygon
			(pts
				(xy 190.664084 -17.272508) (xy 190.839344 -17.272508) (xy 190.867284 -17.244568) (xy 190.867284 -15.850108)
				(xy 190.844424 -15.827248) (xy 190.674244 -15.827248) (xy 190.653924 -15.847568) (xy 190.653924 -17.262348)
			)
		)
	)
	(zone
		(layer "F.Cu")
		(hatch none 0.5)
		(connect_pads
			(clearance 0)
		)
		(min_thickness 0.25)
		(keepout
			(tracks not_allowed)
			(vias allowed)
			(pads allowed)
			(copperpour not_allowed)
			(footprints allowed)
		)
		(placement
			(enabled no)
			(sheetname "")
		)
		(fill
			(thermal_gap 0.5)
			(thermal_bridge_width 0.5)
			(island_removal_mode 0)
		)
		(polygon
			(pts
				(arc
					(start 7.53999 -347.700092)
					(mid 10.340086 -344.899996)
					(end 13.139928 -347.700092)
				)
				(arc
					(start 13.139928 -347.700092)
					(mid 10.340086 -350.499934)
					(end 7.53999 -347.700092)
				)
			)
		)
	)
	(zone
		(layer "F.Cu")
		(hatch none 0.5)
		(connect_pads
			(clearance 0)
		)
		(min_thickness 0.25)
		(keepout
			(tracks allowed)
			(vias allowed)
			(pads allowed)
			(copperpour allowed)
			(footprints allowed)
		)
		(placement
			(enabled no)
			(sheetname "")
		)
		(fill
			(thermal_gap 0.5)
			(thermal_bridge_width 0.5)
			(island_removal_mode 0)
		)
		(polygon
			(pts
				(xy 56.37911 -289.766502) (xy 56.37911 -289.322764) (xy 58.704226 -289.322764) (xy 58.704226 -289.766502)
			)
		)
	)
	(zone
		(layer "F.Cu")
		(hatch none 0.5)
		(connect_pads
			(clearance 0)
		)
		(min_thickness 0.25)
		(keepout
			(tracks allowed)
			(vias allowed)
			(pads allowed)
			(copperpour allowed)
			(footprints allowed)
		)
		(placement
			(enabled no)
			(sheetname "")
		)
		(fill
			(thermal_gap 0.5)
			(thermal_bridge_width 0.5)
			(island_removal_mode 0)
		)
		(polygon
			(pts
				(xy 334.5053 -217.698828) (xy 334.79232 -217.698828) (xy 334.8228 -217.668348) (xy 334.8228 -217.040968)
				(xy 334.73644 -216.954608) (xy 334.54848 -216.954608) (xy 334.47482 -217.028268) (xy 334.47482 -217.668348)
			)
		)
	)
	(zone
		(layer "F.Cu")
		(hatch none 0.5)
		(connect_pads
			(clearance 0)
		)
		(min_thickness 0.25)
		(keepout
			(tracks allowed)
			(vias allowed)
			(pads allowed)
			(copperpour allowed)
			(footprints allowed)
		)
		(placement
			(enabled no)
			(sheetname "")
		)
		(fill
			(thermal_gap 0.5)
			(thermal_bridge_width 0.5)
			(island_removal_mode 0)
		)
		(polygon
			(pts
				(xy 331.931518 -237.49254) (xy 331.441552 -237.49254) (xy 331.373734 -237.49254) (xy 331.331062 -237.449868)
				(xy 331.331062 -233.813096) (xy 331.458824 -233.685334) (xy 331.679296 -233.685334) (xy 331.753972 -233.610658)
				(xy 331.753972 -233.052112) (xy 331.74051 -233.03865) (xy 331.593952 -233.03865) (xy 331.386942 -233.03865)
				(xy 331.309472 -232.96118) (xy 331.309472 -231.198166) (xy 331.722476 -230.785162) (xy 331.722476 -229.860856)
				(xy 331.291184 -229.429564) (xy 331.22108 -229.35946) (xy 331.22108 -229.27564) (xy 331.630528 -228.866192)
				(xy 331.904086 -228.866192) (xy 331.99705 -228.773228) (xy 331.99705 -227.904802) (xy 331.796898 -227.70465)
				(xy 331.796898 -222.95612) (xy 331.56779 -222.727012) (xy 331.56779 -222.726758) (xy 331.568298 -222.72625)
				(xy 331.339698 -222.49765) (xy 331.261974 -222.419926) (xy 331.261974 -221.937326) (xy 331.261974 -221.839282)
				(xy 332.06436 -221.036896) (xy 331.137006 -220.109542) (xy 331.055472 -220.028008) (xy 331.055472 -219.932758)
				(xy 331.425296 -219.562934) (xy 331.531722 -219.562934) (xy 331.698854 -219.730066) (xy 331.70876 -219.730066)
				(xy 332.990698 -218.448128) (xy 332.990698 -218.10472) (xy 333.37754 -217.717878) (xy 333.37754 -217.658442)
				(xy 333.35341 -217.634312) (xy 333.353156 -215.81364) (xy 333.497174 -215.669622) (xy 334.09509 -215.669622)
				(xy 334.44942 -215.669622) (xy 335.619852 -214.49919) (xy 335.619852 -214.09152) (xy 335.619852 -213.986618)
				(xy 335.599786 -213.966552) (xy 328.621644 -213.966552) (xy 328.621644 -212.845904) (xy 328.151744 -212.376004)
				(xy 328.046334 -212.376004) (xy 326.478646 -213.943692) (xy 326.478646 -214.049102) (xy 326.478646 -215.236552)
				(xy 326.443086 -215.272112) (xy 324.698106 -217.017092) (xy 324.698106 -217.22842) (xy 324.837298 -217.367612)
				(xy 325.181722 -217.712036) (xy 325.181722 -217.787728) (xy 324.805802 -218.163648) (xy 324.54469 -218.163648)
				(xy 324.477634 -218.230704) (xy 324.253606 -218.454732) (xy 324.253606 -218.550744) (xy 323.989446 -218.814904)
				(xy 323.49059 -219.31376) (xy 323.448426 -219.355924) (xy 323.448426 -219.686632) (xy 323.821298 -220.059504)
				(xy 323.999606 -220.059504) (xy 324.481698 -220.059504) (xy 324.481698 -220.618304) (xy 324.380098 -220.719904)
				(xy 324.390766 -220.730572) (xy 324.390766 -224.053654) (xy 324.982586 -224.645474) (xy 324.982586 -225.221292)
				(xy 324.418706 -225.785172) (xy 324.418706 -226.183952) (xy 324.164706 -226.437952) (xy 324.164706 -226.477322)
				(xy 324.164706 -228.198172) (xy 324.063106 -228.198172) (xy 324.063106 -230.220012) (xy 324.174866 -230.220012)
				(xy 324.174866 -231.692958) (xy 324.253098 -231.692958) (xy 324.761098 -231.692958) (xy 324.761352 -232.097072)
				(xy 325.091806 -232.097072) (xy 325.091806 -232.885234) (xy 325.16826 -232.885234) (xy 325.670926 -232.885234)
				(xy 325.670926 -233.521504) (xy 325.726552 -233.521504) (xy 326.031352 -233.521504) (xy 326.031352 -233.963972)
				(xy 326.300084 -233.963972) (xy 328.232262 -235.895896) (xy 328.232262 -237.097316) (xy 328.3077 -237.172754)
				(xy 328.392282 -237.257336) (xy 328.392282 -238.483648) (xy 328.812906 -238.904272) (xy 328.812906 -240.656618)
				(xy 328.901552 -240.745264) (xy 329.564746 -240.745264) (xy 329.564746 -241.743992) (xy 329.536806 -241.771932)
				(xy 329.536806 -244.486684) (xy 329.529186 -244.494304) (xy 321.832986 -244.494304) (xy 321.615054 -244.276372)
				(xy 321.295776 -244.276372) (xy 321.077844 -244.494304) (xy 321.077844 -244.957092) (xy 320.852546 -245.18239)
				(xy 320.852546 -245.457472) (xy 321.035426 -245.640352) (xy 321.035426 -245.724172) (xy 320.804286 -245.955312)
				(xy 320.804286 -246.08917) (xy 320.804286 -246.620792) (xy 320.570606 -246.854726) (xy 320.529966 -246.895366)
				(xy 320.529966 -247.362472) (xy 321.102228 -247.934734) (xy 321.192398 -247.934734) (xy 321.291966 -247.934734)
				(xy 321.678046 -248.320814) (xy 321.788536 -248.320814) (xy 321.904106 -248.320814) (xy 322.231766 -248.648474)
				(xy 322.38823 -248.648474) (xy 322.419726 -248.648474) (xy 322.696586 -248.925334) (xy 322.817236 -248.925334)
				(xy 323.176646 -248.925334) (xy 323.407786 -249.156474) (xy 323.530976 -249.156474) (xy 323.801486 -249.156474)
				(xy 324.118986 -249.473974) (xy 324.229476 -249.473974) (xy 324.276466 -249.473974) (xy 324.553326 -249.750834)
				(xy 324.633336 -249.750834) (xy 331.751432 -249.75058) (xy 331.751432 -249.325892) (xy 331.707744 -249.282204)
				(xy 331.57668 -249.282204) (xy 331.56271 -249.268234) (xy 331.56271 -248.724674) (xy 331.840332 -248.447052)
				(xy 331.840332 -247.97512) (xy 331.667866 -247.802654) (xy 331.667866 -245.9228) (xy 331.959204 -245.9228)
				(xy 331.959204 -244.758972) (xy 331.669898 -244.758972) (xy 331.669898 -242.105434) (xy 330.678282 -241.113818)
				(xy 330.678282 -239.666018) (xy 331.20965 -239.13465) (xy 331.384656 -239.13465) (xy 331.796898 -238.722408)
				(xy 331.796898 -238.424974) (xy 331.979524 -238.242348) (xy 331.979524 -237.687358) (xy 331.931518 -237.639352)
			)
		)
	)
	(zone
		(layer "F.Cu")
		(hatch none 0.5)
		(connect_pads
			(clearance 0)
		)
		(min_thickness 0.25)
		(keepout
			(tracks allowed)
			(vias allowed)
			(pads allowed)
			(copperpour allowed)
			(footprints not_allowed)
		)
		(placement
			(enabled no)
			(sheetname "")
		)
		(fill
			(thermal_gap 0.5)
			(thermal_bridge_width 0.5)
			(island_removal_mode 0)
		)
		(polygon
			(pts
				(arc
					(start 108.374942 -431.360072)
					(mid 112.024922 -427.710092)
					(end 115.674902 -431.360072)
				)
				(arc
					(start 115.674902 -431.360072)
					(mid 112.024922 -435.010052)
					(end 108.374942 -431.360072)
				)
			)
		)
	)
	(zone
		(layer "F.Cu")
		(hatch none 0.5)
		(connect_pads
			(clearance 0)
		)
		(min_thickness 0.25)
		(keepout
			(tracks allowed)
			(vias allowed)
			(pads allowed)
			(copperpour allowed)
			(footprints allowed)
		)
		(placement
			(enabled no)
			(sheetname "")
		)
		(fill
			(thermal_gap 0.5)
			(thermal_bridge_width 0.5)
			(island_removal_mode 0)
		)
		(polygon
			(pts
				(xy 361.25023 -335.958942) (xy 359.50271 -335.958942) (xy 359.50271 -334.023462) (xy 361.25023 -334.023462)
			)
		)
	)
	(zone
		(layer "F.Cu")
		(hatch none 0.5)
		(connect_pads
			(clearance 0)
		)
		(min_thickness 0.25)
		(keepout
			(tracks allowed)
			(vias allowed)
			(pads allowed)
			(copperpour allowed)
			(footprints allowed)
		)
		(placement
			(enabled no)
			(sheetname "")
		)
		(fill
			(thermal_gap 0.5)
			(thermal_bridge_width 0.5)
			(island_removal_mode 0)
		)
		(polygon
			(pts
				(xy 455.094594 -238.426244) (xy 457.126594 -238.426244) (xy 457.126594 -238.654844) (xy 455.094594 -238.654844)
				(xy 454.963276 -238.654844) (xy 454.937368 -238.654844) (xy 454.937368 -238.426244) (xy 454.963276 -238.426244)
			)
		)
	)
	(zone
		(layer "F.Cu")
		(hatch none 0.5)
		(connect_pads
			(clearance 0)
		)
		(min_thickness 0.25)
		(keepout
			(tracks allowed)
			(vias allowed)
			(pads allowed)
			(copperpour allowed)
			(footprints allowed)
		)
		(placement
			(enabled no)
			(sheetname "")
		)
		(fill
			(thermal_gap 0.5)
			(thermal_bridge_width 0.5)
			(island_removal_mode 0)
		)
		(polygon
			(pts
				(xy 259.056378 -224.316544) (xy 259.056378 -223.872806) (xy 261.381494 -223.872806) (xy 261.381494 -224.316544)
			)
		)
	)
	(zone
		(layer "F.Cu")
		(hatch none 0.5)
		(connect_pads
			(clearance 0)
		)
		(min_thickness 0.25)
		(keepout
			(tracks allowed)
			(vias allowed)
			(pads allowed)
			(copperpour allowed)
			(footprints allowed)
		)
		(placement
			(enabled no)
			(sheetname "")
		)
		(fill
			(thermal_gap 0.5)
			(thermal_bridge_width 0.5)
			(island_removal_mode 0)
		)
		(polygon
			(pts
				(xy 161.891726 -229.07625) (xy 163.923726 -229.07625) (xy 163.923726 -229.30485) (xy 161.891726 -229.30485)
				(xy 161.7218 -229.30485) (xy 161.701988 -229.30485) (xy 161.701988 -229.07625) (xy 161.7218 -229.07625)
			)
		)
	)
	(zone
		(layer "F.Cu")
		(hatch none 0.5)
		(connect_pads
			(clearance 0)
		)
		(min_thickness 0.25)
		(keepout
			(tracks allowed)
			(vias allowed)
			(pads allowed)
			(copperpour allowed)
			(footprints allowed)
		)
		(placement
			(enabled no)
			(sheetname "")
		)
		(fill
			(thermal_gap 0.5)
			(thermal_bridge_width 0.5)
			(island_removal_mode 0)
		)
		(polygon
			(pts
				(xy 389.532368 -18.55978) (xy 389.532368 -15.425166) (xy 391.31113 -15.425166) (xy 391.31113 -18.55978)
			)
		)
	)
	(zone
		(layer "F.Cu")
		(hatch none 0.5)
		(connect_pads
			(clearance 0)
		)
		(min_thickness 0.25)
		(keepout
			(tracks allowed)
			(vias allowed)
			(pads allowed)
			(copperpour allowed)
			(footprints not_allowed)
		)
		(placement
			(enabled no)
			(sheetname "")
		)
		(fill
			(thermal_gap 0.5)
			(thermal_bridge_width 0.5)
			(island_removal_mode 0)
		)
		(polygon
			(pts
				(xy 380.499874 -440.989974) (xy 380.499874 -421.09009) (xy 414.399984 -421.09009) (xy 414.399984 -440.989974)
				(xy 417.599876 -440.989974) (xy 417.599876 -417.889944) (xy 377.299982 -417.889944) (xy 377.299982 -440.989974)
			)
		)
	)
	(zone
		(layer "F.Cu")
		(hatch none 0.5)
		(connect_pads
			(clearance 0)
		)
		(min_thickness 0.25)
		(keepout
			(tracks allowed)
			(vias allowed)
			(pads allowed)
			(copperpour allowed)
			(footprints allowed)
		)
		(placement
			(enabled no)
			(sheetname "")
		)
		(fill
			(thermal_gap 0.5)
			(thermal_bridge_width 0.5)
			(island_removal_mode 0)
		)
		(polygon
			(pts
				(xy 23.75408 -5.977128) (xy 23.75408 -4.023868) (xy 25.80132 -4.023868) (xy 25.80132 -5.977128)
			)
		)
	)
	(zone
		(layer "F.Cu")
		(hatch none 0.5)
		(connect_pads
			(clearance 0)
		)
		(min_thickness 0.25)
		(keepout
			(tracks allowed)
			(vias allowed)
			(pads allowed)
			(copperpour allowed)
			(footprints allowed)
		)
		(placement
			(enabled no)
			(sheetname "")
		)
		(fill
			(thermal_gap 0.5)
			(thermal_bridge_width 0.5)
			(island_removal_mode 0)
		)
		(polygon
			(pts
				(xy 311.94248 -316.116462) (xy 311.94248 -315.672724) (xy 314.12688 -315.672724) (xy 314.12688 -316.116462)
			)
		)
	)
	(zone
		(layer "F.Cu")
		(hatch none 0.5)
		(connect_pads
			(clearance 0)
		)
		(min_thickness 0.25)
		(keepout
			(tracks allowed)
			(vias allowed)
			(pads allowed)
			(copperpour allowed)
			(footprints allowed)
		)
		(placement
			(enabled no)
			(sheetname "")
		)
		(fill
			(thermal_gap 0.5)
			(thermal_bridge_width 0.5)
			(island_removal_mode 0)
		)
		(polygon
			(pts
				(xy 455.094594 -275.82622) (xy 457.126594 -275.82622) (xy 457.126594 -276.05482) (xy 455.094594 -276.05482)
				(xy 454.963276 -276.05482) (xy 454.937368 -276.05482) (xy 454.937368 -275.82622) (xy 454.963276 -275.82622)
			)
		)
	)
	(zone
		(layer "F.Cu")
		(hatch none 0.5)
		(connect_pads
			(clearance 0)
		)
		(min_thickness 0.25)
		(keepout
			(tracks not_allowed)
			(vias allowed)
			(pads allowed)
			(copperpour not_allowed)
			(footprints allowed)
		)
		(placement
			(enabled no)
			(sheetname "")
		)
		(fill
			(thermal_gap 0.5)
			(thermal_bridge_width 0.5)
			(island_removal_mode 0)
		)
		(polygon
			(pts
				(xy 367.616994 -335.351628) (xy 367.616994 -334.355948) (xy 367.374678 -334.355948) (xy 367.374678 -335.425288)
				(xy 367.543334 -335.425288)
			)
		)
	)
	(zone
		(layer "F.Cu")
		(hatch none 0.5)
		(connect_pads
			(clearance 0)
		)
		(min_thickness 0.25)
		(keepout
			(tracks allowed)
			(vias allowed)
			(pads allowed)
			(copperpour allowed)
			(footprints allowed)
		)
		(placement
			(enabled no)
			(sheetname "")
		)
		(fill
			(thermal_gap 0.5)
			(thermal_bridge_width 0.5)
			(island_removal_mode 0)
		)
		(polygon
			(pts
				(xy 15.024862 -18.570702) (xy 15.024862 -15.436088) (xy 16.803624 -15.436088) (xy 16.803624 -18.570702)
			)
		)
	)
	(zone
		(layer "F.Cu")
		(hatch none 0.5)
		(connect_pads
			(clearance 0)
		)
		(min_thickness 0.25)
		(keepout
			(tracks allowed)
			(vias allowed)
			(pads allowed)
			(copperpour allowed)
			(footprints allowed)
		)
		(placement
			(enabled no)
			(sheetname "")
		)
		(fill
			(thermal_gap 0.5)
			(thermal_bridge_width 0.5)
			(island_removal_mode 0)
		)
		(polygon
			(pts
				(xy 259.056378 -202.216512) (xy 259.056378 -201.772774) (xy 261.381494 -201.772774) (xy 261.381494 -202.216512)
			)
		)
	)
	(zone
		(layer "F.Cu")
		(hatch none 0.5)
		(connect_pads
			(clearance 0)
		)
		(min_thickness 0.25)
		(keepout
			(tracks allowed)
			(vias allowed)
			(pads allowed)
			(copperpour allowed)
			(footprints allowed)
		)
		(placement
			(enabled no)
			(sheetname "")
		)
		(fill
			(thermal_gap 0.5)
			(thermal_bridge_width 0.5)
			(island_removal_mode 0)
		)
		(polygon
			(pts
				(xy 111.16818 -321.366388) (xy 111.16818 -319.154048) (xy 115.443 -319.154048) (xy 115.443 -321.366388)
			)
		)
	)
	(zone
		(layer "F.Cu")
		(hatch none 0.5)
		(connect_pads
			(clearance 0)
		)
		(min_thickness 0.25)
		(keepout
			(tracks allowed)
			(vias allowed)
			(pads allowed)
			(copperpour allowed)
			(footprints allowed)
		)
		(placement
			(enabled no)
			(sheetname "")
		)
		(fill
			(thermal_gap 0.5)
			(thermal_bridge_width 0.5)
			(island_removal_mode 0)
		)
		(polygon
			(pts
				(xy 210.598258 -208.054956) (xy 210.598258 -207.826356) (xy 212.630258 -207.826356) (xy 212.630258 -208.054956)
			)
		)
	)
	(zone
		(layer "F.Cu")
		(hatch none 0.5)
		(connect_pads
			(clearance 0)
		)
		(min_thickness 0.25)
		(keepout
			(tracks allowed)
			(vias allowed)
			(pads allowed)
			(copperpour allowed)
			(footprints allowed)
		)
		(placement
			(enabled no)
			(sheetname "")
		)
		(fill
			(thermal_gap 0.5)
			(thermal_bridge_width 0.5)
			(island_removal_mode 0)
		)
		(polygon
			(pts
				(xy 262.50011 -273.61642) (xy 262.50011 -273.172682) (xy 264.825226 -273.172682) (xy 264.825226 -273.61642)
			)
		)
	)
	(zone
		(layer "F.Cu")
		(hatch none 0.5)
		(connect_pads
			(clearance 0)
		)
		(min_thickness 0.25)
		(keepout
			(tracks allowed)
			(vias allowed)
			(pads allowed)
			(copperpour allowed)
			(footprints allowed)
		)
		(placement
			(enabled no)
			(sheetname "")
		)
		(fill
			(thermal_gap 0.5)
			(thermal_bridge_width 0.5)
			(island_removal_mode 0)
		)
		(polygon
			(pts
				(xy 259.056378 -197.966584) (xy 259.056378 -197.522846) (xy 261.381494 -197.522846) (xy 261.381494 -197.966584)
			)
		)
	)
	(zone
		(layer "F.Cu")
		(hatch none 0.5)
		(connect_pads
			(clearance 0)
		)
		(min_thickness 0.25)
		(keepout
			(tracks allowed)
			(vias allowed)
			(pads allowed)
			(copperpour allowed)
			(footprints allowed)
		)
		(placement
			(enabled no)
			(sheetname "")
		)
		(fill
			(thermal_gap 0.5)
			(thermal_bridge_width 0.5)
			(island_removal_mode 0)
		)
		(polygon
			(pts
				(xy 41.29151 -313.566556) (xy 41.29151 -313.122818) (xy 43.616626 -313.122818) (xy 43.616626 -313.566556)
			)
		)
	)
	(zone
		(layer "F.Cu")
		(hatch none 0.5)
		(connect_pads
			(clearance 0)
		)
		(min_thickness 0.25)
		(keepout
			(tracks allowed)
			(vias allowed)
			(pads allowed)
			(copperpour allowed)
			(footprints allowed)
		)
		(placement
			(enabled no)
			(sheetname "")
		)
		(fill
			(thermal_gap 0.5)
			(thermal_bridge_width 0.5)
			(island_removal_mode 0)
		)
		(polygon
			(pts
				(xy 157.791658 -207.204818) (xy 157.791658 -206.976218) (xy 159.823658 -206.976218) (xy 159.823658 -207.204818)
			)
		)
	)
	(zone
		(layer "F.Cu")
		(hatch none 0.5)
		(connect_pads
			(clearance 0)
		)
		(min_thickness 0.25)
		(keepout
			(tracks allowed)
			(vias allowed)
			(pads allowed)
			(copperpour allowed)
			(footprints allowed)
		)
		(placement
			(enabled no)
			(sheetname "")
		)
		(fill
			(thermal_gap 0.5)
			(thermal_bridge_width 0.5)
			(island_removal_mode 0)
		)
		(polygon
			(pts
				(xy 165.335458 -198.704962) (xy 165.335458 -198.476362) (xy 167.367458 -198.476362) (xy 167.367458 -198.704962)
			)
		)
	)
	(zone
		(layer "F.Cu")
		(hatch none 0.5)
		(connect_pads
			(clearance 0)
		)
		(min_thickness 0.25)
		(keepout
			(tracks allowed)
			(vias allowed)
			(pads allowed)
			(copperpour allowed)
			(footprints allowed)
		)
		(placement
			(enabled no)
			(sheetname "")
		)
		(fill
			(thermal_gap 0.5)
			(thermal_bridge_width 0.5)
			(island_removal_mode 0)
		)
		(polygon
			(pts
				(xy 44.735242 -262.566658) (xy 44.735242 -262.12292) (xy 47.060358 -262.12292) (xy 47.060358 -262.566658)
			)
		)
	)
	(zone
		(layer "F.Cu")
		(hatch none 0.5)
		(connect_pads
			(clearance 0)
		)
		(min_thickness 0.25)
		(keepout
			(tracks allowed)
			(vias allowed)
			(pads allowed)
			(copperpour allowed)
			(footprints allowed)
		)
		(placement
			(enabled no)
			(sheetname "")
		)
		(fill
			(thermal_gap 0.5)
			(thermal_bridge_width 0.5)
			(island_removal_mode 0)
		)
		(polygon
			(pts
				(xy 192.066926 -313.226196) (xy 194.098926 -313.226196) (xy 194.098926 -313.454796) (xy 192.066926 -313.454796)
				(xy 191.935608 -313.454796) (xy 191.9097 -313.454796) (xy 191.9097 -313.226196) (xy 191.935608 -313.226196)
			)
		)
	)
	(zone
		(layer "F.Cu")
		(hatch none 0.5)
		(connect_pads
			(clearance 0)
		)
		(min_thickness 0.25)
		(keepout
			(tracks allowed)
			(vias allowed)
			(pads allowed)
			(copperpour allowed)
			(footprints allowed)
		)
		(placement
			(enabled no)
			(sheetname "")
		)
		(fill
			(thermal_gap 0.5)
			(thermal_bridge_width 0.5)
			(island_removal_mode 0)
		)
		(polygon
			(pts
				(xy 413.275526 -269.254986) (xy 413.275526 -269.026386) (xy 415.307526 -269.026386) (xy 415.307526 -269.254986)
			)
		)
	)
	(zone
		(layer "F.Cu")
		(hatch none 0.5)
		(connect_pads
			(clearance 0)
		)
		(min_thickness 0.25)
		(keepout
			(tracks allowed)
			(vias allowed)
			(pads allowed)
			(copperpour allowed)
			(footprints allowed)
		)
		(placement
			(enabled no)
			(sheetname "")
		)
		(fill
			(thermal_gap 0.5)
			(thermal_bridge_width 0.5)
			(island_removal_mode 0)
		)
		(polygon
			(pts
				(xy 161.891726 -266.704826) (xy 161.891726 -266.476226) (xy 163.923726 -266.476226) (xy 163.923726 -266.704826)
			)
		)
	)
	(zone
		(layer "F.Cu")
		(hatch none 0.5)
		(connect_pads
			(clearance 0)
		)
		(min_thickness 0.25)
		(keepout
			(tracks allowed)
			(vias allowed)
			(pads allowed)
			(copperpour allowed)
			(footprints allowed)
		)
		(placement
			(enabled no)
			(sheetname "")
		)
		(fill
			(thermal_gap 0.5)
			(thermal_bridge_width 0.5)
			(island_removal_mode 0)
		)
		(polygon
			(pts
				(xy 311.91708 -261.71652) (xy 311.91708 -261.272782) (xy 314.15228 -261.272782) (xy 314.15228 -261.71652)
			)
		)
	)
	(zone
		(layer "F.Cu")
		(hatch none 0.5)
		(connect_pads
			(clearance 0)
		)
		(min_thickness 0.25)
		(keepout
			(tracks allowed)
			(vias allowed)
			(pads allowed)
			(copperpour allowed)
			(footprints allowed)
		)
		(placement
			(enabled no)
			(sheetname "")
		)
		(fill
			(thermal_gap 0.5)
			(thermal_bridge_width 0.5)
			(island_removal_mode 0)
		)
		(polygon
			(pts
				(xy 63.92291 -287.216596) (xy 63.92291 -286.772858) (xy 66.248026 -286.772858) (xy 66.248026 -287.216596)
			)
		)
	)
	(zone
		(layer "F.Cu")
		(hatch none 0.5)
		(connect_pads
			(clearance 0)
		)
		(min_thickness 0.25)
		(keepout
			(tracks allowed)
			(vias allowed)
			(pads allowed)
			(copperpour allowed)
			(footprints allowed)
		)
		(placement
			(enabled no)
			(sheetname "")
		)
		(fill
			(thermal_gap 0.5)
			(thermal_bridge_width 0.5)
			(island_removal_mode 0)
		)
		(polygon
			(pts
				(xy 56.37911 -216.666572) (xy 56.37911 -216.222834) (xy 58.704226 -216.222834) (xy 58.704226 -216.666572)
			)
		)
	)
	(zone
		(layer "F.Cu")
		(hatch none 0.5)
		(connect_pads
			(clearance 0)
		)
		(min_thickness 0.25)
		(keepout
			(tracks allowed)
			(vias allowed)
			(pads allowed)
			(copperpour allowed)
			(footprints allowed)
		)
		(placement
			(enabled no)
			(sheetname "")
		)
		(fill
			(thermal_gap 0.5)
			(thermal_bridge_width 0.5)
			(island_removal_mode 0)
		)
		(polygon
			(pts
				(xy 26.20391 -295.716452) (xy 26.20391 -295.272714) (xy 28.529026 -295.272714) (xy 28.529026 -295.716452)
			)
		)
	)
	(zone
		(layer "F.Cu")
		(hatch none 0.5)
		(connect_pads
			(clearance 0)
		)
		(min_thickness 0.25)
		(keepout
			(tracks allowed)
			(vias allowed)
			(pads allowed)
			(copperpour allowed)
			(footprints allowed)
		)
		(placement
			(enabled no)
			(sheetname "")
		)
		(fill
			(thermal_gap 0.5)
			(thermal_bridge_width 0.5)
			(island_removal_mode 0)
		)
		(polygon
			(pts
				(xy 11.11631 -262.566658) (xy 11.11631 -262.12292) (xy 13.441426 -262.12292) (xy 13.441426 -262.566658)
			)
		)
	)
	(zone
		(layer "F.Cu")
		(hatch none 0.5)
		(connect_pads
			(clearance 0)
		)
		(min_thickness 0.25)
		(keepout
			(tracks allowed)
			(vias allowed)
			(pads allowed)
			(copperpour allowed)
			(footprints allowed)
		)
		(placement
			(enabled no)
			(sheetname "")
		)
		(fill
			(thermal_gap 0.5)
			(thermal_bridge_width 0.5)
			(island_removal_mode 0)
		)
		(polygon
			(pts
				(xy 306.644294 -276.16658) (xy 304.319178 -276.16658) (xy 303.976532 -276.16658) (xy 303.976532 -274.911312)
				(xy 306.68468 -274.911312) (xy 306.68468 -276.16658)
			)
		)
	)
	(zone
		(layer "F.Cu")
		(hatch none 0.5)
		(connect_pads
			(clearance 0)
		)
		(min_thickness 0.25)
		(keepout
			(tracks allowed)
			(vias allowed)
			(pads allowed)
			(copperpour allowed)
			(footprints allowed)
		)
		(placement
			(enabled no)
			(sheetname "")
		)
		(fill
			(thermal_gap 0.5)
			(thermal_bridge_width 0.5)
			(island_removal_mode 0)
		)
		(polygon
			(pts
				(xy 51.245008 -355.790754) (xy 49.497488 -355.790754) (xy 49.497488 -353.855274) (xy 51.245008 -353.855274)
			)
		)
	)
	(zone
		(layer "F.Cu")
		(hatch none 0.5)
		(connect_pads
			(clearance 0)
		)
		(min_thickness 0.25)
		(keepout
			(tracks allowed)
			(vias allowed)
			(pads allowed)
			(copperpour allowed)
			(footprints allowed)
		)
		(placement
			(enabled no)
			(sheetname "")
		)
		(fill
			(thermal_gap 0.5)
			(thermal_bridge_width 0.5)
			(island_removal_mode 0)
		)
		(polygon
			(pts
				(xy 277.58771 -265.966448) (xy 277.58771 -265.52271) (xy 279.912826 -265.52271) (xy 279.912826 -265.966448)
			)
		)
	)
	(zone
		(layer "F.Cu")
		(hatch none 0.5)
		(connect_pads
			(clearance 0)
		)
		(min_thickness 0.25)
		(keepout
			(tracks allowed)
			(vias allowed)
			(pads allowed)
			(copperpour allowed)
			(footprints allowed)
		)
		(placement
			(enabled no)
			(sheetname "")
		)
		(fill
			(thermal_gap 0.5)
			(thermal_bridge_width 0.5)
			(island_removal_mode 0)
		)
		(polygon
			(pts
				(xy 14.560042 -209.0166) (xy 14.560042 -208.572862) (xy 16.885158 -208.572862) (xy 16.885158 -209.0166)
			)
		)
	)
	(zone
		(layer "F.Cu")
		(hatch none 0.5)
		(connect_pads
			(clearance 0)
		)
		(min_thickness 0.25)
		(keepout
			(tracks allowed)
			(vias allowed)
			(pads allowed)
			(copperpour allowed)
			(footprints not_allowed)
		)
		(placement
			(enabled no)
			(sheetname "")
		)
		(fill
			(thermal_gap 0.5)
			(thermal_bridge_width 0.5)
			(island_removal_mode 0)
		)
		(polygon
			(pts
				(arc
					(start 351.899982 -28.450032)
					(mid 356.899972 -23.450042)
					(end 361.899962 -28.450032)
				)
				(arc
					(start 361.899962 -28.450032)
					(mid 356.899972 -33.450022)
					(end 351.899982 -28.450032)
				)
			)
		)
	)
	(zone
		(layer "F.Cu")
		(hatch none 0.5)
		(connect_pads
			(clearance 0)
		)
		(min_thickness 0.25)
		(keepout
			(tracks allowed)
			(vias allowed)
			(pads allowed)
			(copperpour allowed)
			(footprints allowed)
		)
		(placement
			(enabled no)
			(sheetname "")
		)
		(fill
			(thermal_gap 0.5)
			(thermal_bridge_width 0.5)
			(island_removal_mode 0)
		)
		(polygon
			(pts
				(xy 405.731726 -213.155022) (xy 405.731726 -212.926422) (xy 407.763726 -212.926422) (xy 407.763726 -213.155022)
			)
		)
	)
	(zone
		(layer "F.Cu")
		(hatch none 0.5)
		(connect_pads
			(clearance 0)
		)
		(min_thickness 0.25)
		(keepout
			(tracks allowed)
			(vias allowed)
			(pads allowed)
			(copperpour allowed)
			(footprints allowed)
		)
		(placement
			(enabled no)
			(sheetname "")
		)
		(fill
			(thermal_gap 0.5)
			(thermal_bridge_width 0.5)
			(island_removal_mode 0)
		)
		(polygon
			(pts
				(xy 415.880042 -176.81956) (xy 415.880042 -180.35524) (xy 413.797242 -180.35524) (xy 413.797242 -176.81956)
			)
		)
	)
	(zone
		(layer "F.Cu")
		(hatch none 0.5)
		(connect_pads
			(clearance 0)
		)
		(min_thickness 0.25)
		(keepout
			(tracks allowed)
			(vias allowed)
			(pads allowed)
			(copperpour allowed)
			(footprints allowed)
		)
		(placement
			(enabled no)
			(sheetname "")
		)
		(fill
			(thermal_gap 0.5)
			(thermal_bridge_width 0.5)
			(island_removal_mode 0)
		)
		(polygon
			(pts
				(xy 455.094594 -251.176282) (xy 457.126594 -251.176282) (xy 457.126594 -251.404882) (xy 455.094594 -251.404882)
				(xy 454.92797 -251.404882) (xy 454.92797 -251.176282)
			)
		)
	)
	(zone
		(layer "F.Cu")
		(hatch none 0.5)
		(connect_pads
			(clearance 0)
		)
		(min_thickness 0.25)
		(keepout
			(tracks allowed)
			(vias allowed)
			(pads allowed)
			(copperpour allowed)
			(footprints allowed)
		)
		(placement
			(enabled no)
			(sheetname "")
		)
		(fill
			(thermal_gap 0.5)
			(thermal_bridge_width 0.5)
			(island_removal_mode 0)
		)
		(polygon
			(pts
				(xy 259.056378 -210.716622) (xy 259.056378 -210.272884) (xy 261.381494 -210.272884) (xy 261.381494 -210.716622)
			)
		)
	)
	(zone
		(layer "F.Cu")
		(hatch none 0.5)
		(connect_pads
			(clearance 0)
		)
		(min_thickness 0.25)
		(keepout
			(tracks allowed)
			(vias allowed)
			(pads allowed)
			(copperpour allowed)
			(footprints allowed)
		)
		(placement
			(enabled no)
			(sheetname "")
		)
		(fill
			(thermal_gap 0.5)
			(thermal_bridge_width 0.5)
			(island_removal_mode 0)
		)
		(polygon
			(pts
				(xy 39.03218 -351.521268) (xy 39.03218 -355.526848) (xy 39.51224 -356.006908) (xy 41.57726 -356.006908)
				(xy 41.84904 -355.735128) (xy 41.84904 -353.880928) (xy 42.1005 -353.629468) (xy 44.02074 -353.629468)
				(xy 44.4373 -353.212908) (xy 44.4373 -351.721928) (xy 43.7896 -351.074228) (xy 39.47922 -351.074228)
			)
		)
	)
	(zone
		(layer "F.Cu")
		(hatch none 0.5)
		(connect_pads
			(clearance 0)
		)
		(min_thickness 0.25)
		(keepout
			(tracks not_allowed)
			(vias allowed)
			(pads allowed)
			(copperpour not_allowed)
			(footprints allowed)
		)
		(placement
			(enabled no)
			(sheetname "")
		)
		(fill
			(thermal_gap 0.5)
			(thermal_bridge_width 0.5)
			(island_removal_mode 0)
		)
		(polygon
			(pts
				(arc
					(start 451.299834 -435.59984)
					(mid 448.799966 -438.099708)
					(end 446.299844 -435.59984)
				)
				(arc
					(start 446.299844 -435.59984)
					(mid 448.799966 -433.099718)
					(end 451.299834 -435.59984)
				)
			)
		)
	)
	(zone
		(layer "F.Cu")
		(hatch none 0.5)
		(connect_pads
			(clearance 0)
		)
		(min_thickness 0.25)
		(keepout
			(tracks allowed)
			(vias allowed)
			(pads allowed)
			(copperpour allowed)
			(footprints allowed)
		)
		(placement
			(enabled no)
			(sheetname "")
		)
		(fill
			(thermal_gap 0.5)
			(thermal_bridge_width 0.5)
			(island_removal_mode 0)
		)
		(polygon
			(pts
				(xy 161.891726 -289.654996) (xy 161.891726 -289.426396) (xy 163.923726 -289.426396) (xy 163.923726 -289.654996)
			)
		)
	)
	(zone
		(layer "F.Cu")
		(hatch none 0.5)
		(connect_pads
			(clearance 0)
		)
		(min_thickness 0.25)
		(keepout
			(tracks allowed)
			(vias allowed)
			(pads allowed)
			(copperpour allowed)
			(footprints not_allowed)
		)
		(placement
			(enabled no)
			(sheetname "")
		)
		(fill
			(thermal_gap 0.5)
			(thermal_bridge_width 0.5)
			(island_removal_mode 0)
		)
		(polygon
			(pts
				(xy 424.399964 -27.234896) (xy 424.399964 -46.764956) (xy 431.39995 -46.764956) (xy 431.39995 -27.234896)
			)
		)
	)
	(zone
		(layer "F.Cu")
		(hatch none 0.5)
		(connect_pads
			(clearance 0)
		)
		(min_thickness 0.25)
		(keepout
			(tracks allowed)
			(vias allowed)
			(pads allowed)
			(copperpour allowed)
			(footprints allowed)
		)
		(placement
			(enabled no)
			(sheetname "")
		)
		(fill
			(thermal_gap 0.5)
			(thermal_bridge_width 0.5)
			(island_removal_mode 0)
		)
		(polygon
			(pts
				(xy 428.363126 -239.504982) (xy 428.363126 -239.276382) (xy 430.395126 -239.276382) (xy 430.395126 -239.504982)
			)
		)
	)
	(zone
		(layer "F.Cu")
		(hatch none 0.5)
		(connect_pads
			(clearance 0)
		)
		(min_thickness 0.25)
		(keepout
			(tracks allowed)
			(vias allowed)
			(pads allowed)
			(copperpour allowed)
			(footprints allowed)
		)
		(placement
			(enabled no)
			(sheetname "")
		)
		(fill
			(thermal_gap 0.5)
			(thermal_bridge_width 0.5)
			(island_removal_mode 0)
		)
		(polygon
			(pts
				(xy 59.822842 -224.316544) (xy 59.822842 -223.872806) (xy 62.147958 -223.872806) (xy 62.147958 -224.316544)
			)
		)
	)
	(zone
		(layer "F.Cu")
		(hatch none 0.5)
		(connect_pads
			(clearance 0)
		)
		(min_thickness 0.25)
		(keepout
			(tracks allowed)
			(vias allowed)
			(pads allowed)
			(copperpour allowed)
			(footprints allowed)
		)
		(placement
			(enabled no)
			(sheetname "")
		)
		(fill
			(thermal_gap 0.5)
			(thermal_bridge_width 0.5)
			(island_removal_mode 0)
		)
		(polygon
			(pts
				(xy 262.50011 -198.816468) (xy 262.50011 -198.37273) (xy 264.825226 -198.37273) (xy 264.825226 -198.816468)
			)
		)
	)
	(zone
		(layer "F.Cu")
		(hatch none 0.5)
		(connect_pads
			(clearance 0)
		)
		(min_thickness 0.25)
		(keepout
			(tracks allowed)
			(vias allowed)
			(pads allowed)
			(copperpour allowed)
			(footprints allowed)
		)
		(placement
			(enabled no)
			(sheetname "")
		)
		(fill
			(thermal_gap 0.5)
			(thermal_bridge_width 0.5)
			(island_removal_mode 0)
		)
		(polygon
			(pts
				(xy 307.76291 -217.516456) (xy 307.76291 -217.072718) (xy 310.088026 -217.072718) (xy 310.088026 -217.516456)
			)
		)
	)
	(zone
		(layer "F.Cu")
		(hatch none 0.5)
		(connect_pads
			(clearance 0)
		)
		(min_thickness 0.25)
		(keepout
			(tracks allowed)
			(vias allowed)
			(pads allowed)
			(copperpour allowed)
			(footprints allowed)
		)
		(placement
			(enabled no)
			(sheetname "")
		)
		(fill
			(thermal_gap 0.5)
			(thermal_bridge_width 0.5)
			(island_removal_mode 0)
		)
		(polygon
			(pts
				(xy 11.11631 -213.266528) (xy 11.11631 -212.82279) (xy 13.441426 -212.82279) (xy 13.441426 -213.266528)
			)
		)
	)
	(zone
		(layer "F.Cu")
		(hatch none 0.5)
		(connect_pads
			(clearance 0)
		)
		(min_thickness 0.25)
		(keepout
			(tracks allowed)
			(vias allowed)
			(pads allowed)
			(copperpour allowed)
			(footprints allowed)
		)
		(placement
			(enabled no)
			(sheetname "")
		)
		(fill
			(thermal_gap 0.5)
			(thermal_bridge_width 0.5)
			(island_removal_mode 0)
		)
		(polygon
			(pts
				(xy 56.37911 -229.41661) (xy 56.37911 -228.972872) (xy 58.704226 -228.972872) (xy 58.704226 -229.41661)
			)
		)
	)
	(zone
		(layer "F.Cu")
		(hatch none 0.5)
		(connect_pads
			(clearance 0)
		)
		(min_thickness 0.25)
		(keepout
			(tracks allowed)
			(vias allowed)
			(pads allowed)
			(copperpour allowed)
			(footprints allowed)
		)
		(placement
			(enabled no)
			(sheetname "")
		)
		(fill
			(thermal_gap 0.5)
			(thermal_bridge_width 0.5)
			(island_removal_mode 0)
		)
		(polygon
			(pts
				(xy 176.979326 -258.826254) (xy 179.011326 -258.826254) (xy 179.011326 -259.054854) (xy 176.979326 -259.054854)
				(xy 176.803558 -259.054854) (xy 176.803558 -258.826254)
			)
		)
	)
	(zone
		(layer "F.Cu")
		(hatch none 0.5)
		(connect_pads
			(clearance 0)
		)
		(min_thickness 0.25)
		(keepout
			(tracks allowed)
			(vias allowed)
			(pads allowed)
			(copperpour allowed)
			(footprints allowed)
		)
		(placement
			(enabled no)
			(sheetname "")
		)
		(fill
			(thermal_gap 0.5)
			(thermal_bridge_width 0.5)
			(island_removal_mode 0)
		)
		(polygon
			(pts
				(xy 409.903422 -267.554964) (xy 409.903422 -267.326364) (xy 411.783022 -267.326364) (xy 411.783022 -267.554964)
			)
		)
	)
	(zone
		(layer "F.Cu")
		(hatch none 0.5)
		(connect_pads
			(clearance 0)
		)
		(min_thickness 0.25)
		(keepout
			(tracks allowed)
			(vias allowed)
			(pads allowed)
			(copperpour allowed)
			(footprints allowed)
		)
		(placement
			(enabled no)
			(sheetname "")
		)
		(fill
			(thermal_gap 0.5)
			(thermal_bridge_width 0.5)
			(island_removal_mode 0)
		)
		(polygon
			(pts
				(xy 307.76291 -299.116496) (xy 307.76291 -298.672758) (xy 310.088026 -298.672758) (xy 310.088026 -299.116496)
			)
		)
	)
	(zone
		(layer "F.Cu")
		(hatch none 0.5)
		(connect_pads
			(clearance 0)
		)
		(min_thickness 0.25)
		(keepout
			(tracks not_allowed)
			(vias allowed)
			(pads allowed)
			(copperpour not_allowed)
			(footprints allowed)
		)
		(placement
			(enabled no)
			(sheetname "")
		)
		(fill
			(thermal_gap 0.5)
			(thermal_bridge_width 0.5)
			(island_removal_mode 0)
		)
		(polygon
			(pts
				(xy 286.741616 -365.319818) (xy 290.68014 -365.319818) (xy 290.68014 -365.256826) (xy 290.55822 -365.134906)
				(xy 289.12947 -365.134906) (xy 289.12947 -362.975906) (xy 291.286184 -362.975906) (xy 291.286184 -362.726224)
				(xy 288.95802 -362.726224) (xy 288.95802 -363.035088) (xy 288.838132 -363.035088) (xy 288.838132 -365.07928)
				(xy 286.983932 -365.07928) (xy 286.983932 -364.838234) (xy 286.741616 -364.838234)
			)
		)
	)
	(zone
		(layer "F.Cu")
		(hatch none 0.5)
		(connect_pads
			(clearance 0)
		)
		(min_thickness 0.25)
		(keepout
			(tracks not_allowed)
			(vias allowed)
			(pads allowed)
			(copperpour not_allowed)
			(footprints allowed)
		)
		(placement
			(enabled no)
			(sheetname "")
		)
		(fill
			(thermal_gap 0.5)
			(thermal_bridge_width 0.5)
			(island_removal_mode 0)
		)
		(polygon
			(pts
				(arc
					(start 241.649758 -192.499996)
					(mid 236.649768 -197.499986)
					(end 231.649778 -192.499996)
				)
				(arc
					(start 231.649778 -192.499996)
					(mid 236.649768 -187.500006)
					(end 241.649758 -192.499996)
				)
			)
		)
	)
	(zone
		(layer "F.Cu")
		(hatch none 0.5)
		(connect_pads
			(clearance 0)
		)
		(min_thickness 0.25)
		(keepout
			(tracks allowed)
			(vias allowed)
			(pads allowed)
			(copperpour allowed)
			(footprints not_allowed)
		)
		(placement
			(enabled no)
			(sheetname "")
		)
		(fill
			(thermal_gap 0.5)
			(thermal_bridge_width 0.5)
			(island_removal_mode 0)
		)
		(polygon
			(pts
				(xy 201.33945 -374.753886) (xy 226.939856 -374.753886) (xy 226.939856 -350.763586) (xy 201.33945 -350.763586)
			)
		)
	)
	(zone
		(layer "F.Cu")
		(hatch none 0.5)
		(connect_pads
			(clearance 0)
		)
		(min_thickness 0.25)
		(keepout
			(tracks allowed)
			(vias allowed)
			(pads allowed)
			(copperpour allowed)
			(footprints allowed)
		)
		(placement
			(enabled no)
			(sheetname "")
		)
		(fill
			(thermal_gap 0.5)
			(thermal_bridge_width 0.5)
			(island_removal_mode 0)
		)
		(polygon
			(pts
				(xy 59.822842 -305.066446) (xy 59.822842 -304.622708) (xy 62.147958 -304.622708) (xy 62.147958 -305.066446)
			)
		)
	)
	(zone
		(layer "F.Cu")
		(hatch none 0.5)
		(connect_pads
			(clearance 0)
		)
		(min_thickness 0.25)
		(keepout
			(tracks allowed)
			(vias allowed)
			(pads allowed)
			(copperpour allowed)
			(footprints allowed)
		)
		(placement
			(enabled no)
			(sheetname "")
		)
		(fill
			(thermal_gap 0.5)
			(thermal_bridge_width 0.5)
			(island_removal_mode 0)
		)
		(polygon
			(pts
				(xy 410.788104 -404.802594) (xy 410.788104 -399.959576) (xy 412.67253 -399.959576) (xy 412.67253 -404.802594)
			)
		)
	)
	(zone
		(layer "F.Cu")
		(hatch none 0.5)
		(connect_pads
			(clearance 0)
		)
		(min_thickness 0.25)
		(keepout
			(tracks allowed)
			(vias allowed)
			(pads allowed)
			(copperpour allowed)
			(footprints allowed)
		)
		(placement
			(enabled no)
			(sheetname "")
		)
		(fill
			(thermal_gap 0.5)
			(thermal_bridge_width 0.5)
			(island_removal_mode 0)
		)
		(polygon
			(pts
				(xy 41.29151 -288.06648) (xy 41.29151 -287.622742) (xy 43.616626 -287.622742) (xy 43.616626 -288.06648)
			)
		)
	)
	(zone
		(layer "F.Cu")
		(hatch none 0.5)
		(connect_pads
			(clearance 0)
		)
		(min_thickness 0.25)
		(keepout
			(tracks allowed)
			(vias allowed)
			(pads allowed)
			(copperpour allowed)
			(footprints allowed)
		)
		(placement
			(enabled no)
			(sheetname "")
		)
		(fill
			(thermal_gap 0.5)
			(thermal_bridge_width 0.5)
			(island_removal_mode 0)
		)
		(polygon
			(pts
				(xy 192.066926 -309.826406) (xy 194.098926 -309.826406) (xy 194.098926 -310.055006) (xy 192.066926 -310.055006)
				(xy 191.930782 -310.055006) (xy 191.883792 -310.055006) (xy 191.883792 -309.826406) (xy 191.930782 -309.826406)
			)
		)
	)
	(zone
		(layer "F.Cu")
		(hatch none 0.5)
		(connect_pads
			(clearance 0)
		)
		(min_thickness 0.25)
		(keepout
			(tracks allowed)
			(vias allowed)
			(pads allowed)
			(copperpour allowed)
			(footprints allowed)
		)
		(placement
			(enabled no)
			(sheetname "")
		)
		(fill
			(thermal_gap 0.5)
			(thermal_bridge_width 0.5)
			(island_removal_mode 0)
		)
		(polygon
			(pts
				(xy 277.58771 -197.116446) (xy 277.58771 -196.672708) (xy 279.912826 -196.672708) (xy 279.912826 -197.116446)
			)
		)
	)
	(zone
		(layer "F.Cu")
		(hatch none 0.5)
		(connect_pads
			(clearance 0)
		)
		(min_thickness 0.25)
		(keepout
			(tracks allowed)
			(vias allowed)
			(pads allowed)
			(copperpour allowed)
			(footprints allowed)
		)
		(placement
			(enabled no)
			(sheetname "")
		)
		(fill
			(thermal_gap 0.5)
			(thermal_bridge_width 0.5)
			(island_removal_mode 0)
		)
		(polygon
			(pts
				(xy 14.560042 -208.166462) (xy 14.560042 -207.722724) (xy 16.885158 -207.722724) (xy 16.885158 -208.166462)
			)
		)
	)
	(zone
		(layer "F.Cu")
		(hatch none 0.5)
		(connect_pads
			(clearance 0)
		)
		(min_thickness 0.25)
		(keepout
			(tracks allowed)
			(vias allowed)
			(pads allowed)
			(copperpour allowed)
			(footprints allowed)
		)
		(placement
			(enabled no)
			(sheetname "")
		)
		(fill
			(thermal_gap 0.5)
			(thermal_bridge_width 0.5)
			(island_removal_mode 0)
		)
		(polygon
			(pts
				(xy 413.275526 -304.95494) (xy 413.275526 -304.72634) (xy 415.307526 -304.72634) (xy 415.307526 -304.95494)
			)
		)
	)
	(zone
		(layer "F.Cu")
		(hatch none 0.5)
		(connect_pads
			(clearance 0)
		)
		(min_thickness 0.25)
		(keepout
			(tracks allowed)
			(vias allowed)
			(pads allowed)
			(copperpour allowed)
			(footprints allowed)
		)
		(placement
			(enabled no)
			(sheetname "")
		)
		(fill
			(thermal_gap 0.5)
			(thermal_bridge_width 0.5)
			(island_removal_mode 0)
		)
		(polygon
			(pts
				(xy 277.58771 -226.86645) (xy 277.58771 -226.422712) (xy 279.912826 -226.422712) (xy 279.912826 -226.86645)
			)
		)
	)
	(zone
		(layer "F.Cu")
		(hatch none 0.5)
		(connect_pads
			(clearance 0)
		)
		(min_thickness 0.25)
		(keepout
			(tracks allowed)
			(vias allowed)
			(pads allowed)
			(copperpour allowed)
			(footprints allowed)
		)
		(placement
			(enabled no)
			(sheetname "")
		)
		(fill
			(thermal_gap 0.5)
			(thermal_bridge_width 0.5)
			(island_removal_mode 0)
		)
		(polygon
			(pts
				(xy 135.6868 -330.398628) (xy 135.6868 -328.112628) (xy 140.11148 -328.112628) (xy 140.11148 -330.398628)
			)
		)
	)
	(zone
		(layer "F.Cu")
		(hatch none 0.5)
		(connect_pads
			(clearance 0)
		)
		(min_thickness 0.25)
		(keepout
			(tracks allowed)
			(vias allowed)
			(pads allowed)
			(copperpour allowed)
			(footprints allowed)
		)
		(placement
			(enabled no)
			(sheetname "")
		)
		(fill
			(thermal_gap 0.5)
			(thermal_bridge_width 0.5)
			(island_removal_mode 0)
		)
		(polygon
			(pts
				(xy 443.450726 -250.554998) (xy 443.450726 -250.326398) (xy 445.482726 -250.326398) (xy 445.482726 -250.554998)
			)
		)
	)
	(zone
		(layer "F.Cu")
		(hatch none 0.5)
		(connect_pads
			(clearance 0)
		)
		(min_thickness 0.25)
		(keepout
			(tracks allowed)
			(vias allowed)
			(pads allowed)
			(copperpour allowed)
			(footprints allowed)
		)
		(placement
			(enabled no)
			(sheetname "")
		)
		(fill
			(thermal_gap 0.5)
			(thermal_bridge_width 0.5)
			(island_removal_mode 0)
		)
		(polygon
			(pts
				(xy 358.5718 -40.132) (xy 358.5718 -38.03904) (xy 356.90302 -38.03904) (xy 356.90302 -40.132)
			)
		)
	)
	(zone
		(layer "F.Cu")
		(hatch none 0.5)
		(connect_pads
			(clearance 0)
		)
		(min_thickness 0.25)
		(keepout
			(tracks allowed)
			(vias allowed)
			(pads allowed)
			(copperpour allowed)
			(footprints allowed)
		)
		(placement
			(enabled no)
			(sheetname "")
		)
		(fill
			(thermal_gap 0.5)
			(thermal_bridge_width 0.5)
			(island_removal_mode 0)
		)
		(polygon
			(pts
				(xy 63.951612 -297.416474) (xy 63.951612 -296.972736) (xy 66.161412 -296.972736) (xy 66.161412 -297.416474)
			)
		)
	)
	(zone
		(layer "F.Cu")
		(hatch none 0.5)
		(connect_pads
			(clearance 0)
		)
		(min_thickness 0.25)
		(keepout
			(tracks allowed)
			(vias allowed)
			(pads allowed)
			(copperpour allowed)
			(footprints allowed)
		)
		(placement
			(enabled no)
			(sheetname "")
		)
		(fill
			(thermal_gap 0.5)
			(thermal_bridge_width 0.5)
			(island_removal_mode 0)
		)
		(polygon
			(pts
				(xy 161.891726 -219.954856) (xy 161.891726 -219.726256) (xy 163.923726 -219.726256) (xy 163.923726 -219.954856)
			)
		)
	)
	(zone
		(layer "F.Cu")
		(hatch none 0.5)
		(connect_pads
			(clearance 0)
		)
		(min_thickness 0.25)
		(keepout
			(tracks allowed)
			(vias allowed)
			(pads allowed)
			(copperpour allowed)
			(footprints allowed)
		)
		(placement
			(enabled no)
			(sheetname "")
		)
		(fill
			(thermal_gap 0.5)
			(thermal_bridge_width 0.5)
			(island_removal_mode 0)
		)
		(polygon
			(pts
				(xy 418.095176 -170.442128) (xy 416.7632 -170.442128) (xy 416.564318 -170.243246) (xy 416.564318 -168.451276)
				(xy 417.367466 -167.648128) (xy 419.84549 -167.648128) (xy 421.205152 -169.00779) (xy 421.205152 -174.499524)
				(xy 420.065454 -175.639222) (xy 416.144964 -175.639222) (xy 415.51352 -175.007778) (xy 415.51352 -173.291754)
				(xy 416.070034 -172.73524) (xy 418.21862 -172.73524) (xy 418.2872 -172.66666) (xy 418.2872 -170.634152)
			)
		)
	)
	(zone
		(layer "F.Cu")
		(hatch none 0.5)
		(connect_pads
			(clearance 0)
		)
		(min_thickness 0.25)
		(keepout
			(tracks allowed)
			(vias allowed)
			(pads allowed)
			(copperpour allowed)
			(footprints allowed)
		)
		(placement
			(enabled no)
			(sheetname "")
		)
		(fill
			(thermal_gap 0.5)
			(thermal_bridge_width 0.5)
			(island_removal_mode 0)
		)
		(polygon
			(pts
				(xy 161.891726 -291.355018) (xy 161.891726 -291.126418) (xy 163.923726 -291.126418) (xy 163.923726 -291.355018)
			)
		)
	)
	(zone
		(layer "F.Cu")
		(hatch none 0.5)
		(connect_pads
			(clearance 0)
		)
		(min_thickness 0.25)
		(keepout
			(tracks allowed)
			(vias allowed)
			(pads allowed)
			(copperpour allowed)
			(footprints allowed)
		)
		(placement
			(enabled no)
			(sheetname "")
		)
		(fill
			(thermal_gap 0.5)
			(thermal_bridge_width 0.5)
			(island_removal_mode 0)
		)
		(polygon
			(pts
				(xy 347.754702 -410.948886) (xy 347.754702 -406.105868) (xy 349.639128 -406.105868) (xy 349.639128 -410.948886)
			)
		)
	)
	(zone
		(layer "F.Cu")
		(hatch none 0.5)
		(connect_pads
			(clearance 0)
		)
		(min_thickness 0.25)
		(keepout
			(tracks allowed)
			(vias allowed)
			(pads allowed)
			(copperpour allowed)
			(footprints allowed)
		)
		(placement
			(enabled no)
			(sheetname "")
		)
		(fill
			(thermal_gap 0.5)
			(thermal_bridge_width 0.5)
			(island_removal_mode 0)
		)
		(polygon
			(pts
				(xy 440.006994 -223.976438) (xy 442.038994 -223.976438) (xy 442.038994 -224.205038) (xy 440.006994 -224.205038)
				(xy 439.87085 -224.205038) (xy 439.82386 -224.205038) (xy 439.82386 -223.976438) (xy 439.87085 -223.976438)
			)
		)
	)
	(zone
		(layer "F.Cu")
		(hatch none 0.5)
		(connect_pads
			(clearance 0)
		)
		(min_thickness 0.25)
		(keepout
			(tracks allowed)
			(vias allowed)
			(pads allowed)
			(copperpour allowed)
			(footprints allowed)
		)
		(placement
			(enabled no)
			(sheetname "")
		)
		(fill
			(thermal_gap 0.5)
			(thermal_bridge_width 0.5)
			(island_removal_mode 0)
		)
		(polygon
			(pts
				(xy 428.363126 -302.405034) (xy 428.363126 -302.176434) (xy 430.395126 -302.176434) (xy 430.395126 -302.405034)
			)
		)
	)
	(zone
		(layer "F.Cu")
		(hatch none 0.5)
		(connect_pads
			(clearance 0)
		)
		(min_thickness 0.25)
		(keepout
			(tracks allowed)
			(vias allowed)
			(pads allowed)
			(copperpour allowed)
			(footprints allowed)
		)
		(placement
			(enabled no)
			(sheetname "")
		)
		(fill
			(thermal_gap 0.5)
			(thermal_bridge_width 0.5)
			(island_removal_mode 0)
		)
		(polygon
			(pts
				(xy 259.056378 -230.266494) (xy 259.056378 -229.822756) (xy 261.381494 -229.822756) (xy 261.381494 -230.266494)
			)
		)
	)
	(zone
		(layer "F.Cu")
		(hatch none 0.5)
		(connect_pads
			(clearance 0)
		)
		(min_thickness 0.25)
		(keepout
			(tracks allowed)
			(vias allowed)
			(pads allowed)
			(copperpour allowed)
			(footprints allowed)
		)
		(placement
			(enabled no)
			(sheetname "")
		)
		(fill
			(thermal_gap 0.5)
			(thermal_bridge_width 0.5)
			(island_removal_mode 0)
		)
		(polygon
			(pts
				(xy 274.143978 -220.066616) (xy 274.143978 -219.622878) (xy 276.469094 -219.622878) (xy 276.469094 -220.066616)
			)
		)
	)
	(zone
		(layer "F.Cu")
		(hatch none 0.5)
		(connect_pads
			(clearance 0)
		)
		(min_thickness 0.25)
		(keepout
			(tracks allowed)
			(vias allowed)
			(pads allowed)
			(copperpour allowed)
			(footprints not_allowed)
		)
		(placement
			(enabled no)
			(sheetname "")
		)
		(fill
			(thermal_gap 0.5)
			(thermal_bridge_width 0.5)
			(island_removal_mode 0)
		)
		(polygon
			(pts
				(xy 470.019634 -6.780022) (xy 470.019634 -14.780006) (xy 459.019656 -14.780006) (xy 459.019656 -6.780022)
			)
		)
	)
	(zone
		(layer "F.Cu")
		(hatch none 0.5)
		(connect_pads
			(clearance 0)
		)
		(min_thickness 0.25)
		(keepout
			(tracks allowed)
			(vias allowed)
			(pads allowed)
			(copperpour allowed)
			(footprints not_allowed)
		)
		(placement
			(enabled no)
			(sheetname "")
		)
		(fill
			(thermal_gap 0.5)
			(thermal_bridge_width 0.5)
			(island_removal_mode 0)
		)
		(polygon
			(pts
				(xy 203.076302 -330.091796) (xy 209.176112 -330.091796) (xy 209.176112 -186.09183) (xy 203.076302 -186.09183)
			)
		)
	)
	(zone
		(layer "F.Cu")
		(hatch none 0.5)
		(connect_pads
			(clearance 0)
		)
		(min_thickness 0.25)
		(keepout
			(tracks allowed)
			(vias allowed)
			(pads allowed)
			(copperpour allowed)
			(footprints allowed)
		)
		(placement
			(enabled no)
			(sheetname "")
		)
		(fill
			(thermal_gap 0.5)
			(thermal_bridge_width 0.5)
			(island_removal_mode 0)
		)
		(polygon
			(pts
				(xy 262.50011 -214.96655) (xy 262.50011 -214.522812) (xy 264.825226 -214.522812) (xy 264.825226 -214.96655)
			)
		)
	)
	(zone
		(layer "F.Cu")
		(hatch none 0.5)
		(connect_pads
			(clearance 0)
		)
		(min_thickness 0.25)
		(keepout
			(tracks allowed)
			(vias allowed)
			(pads allowed)
			(copperpour allowed)
			(footprints allowed)
		)
		(placement
			(enabled no)
			(sheetname "")
		)
		(fill
			(thermal_gap 0.5)
			(thermal_bridge_width 0.5)
			(island_removal_mode 0)
		)
		(polygon
			(pts
				(xy 424.919394 -245.454932) (xy 424.919394 -245.226332) (xy 426.951394 -245.226332) (xy 426.951394 -245.454932)
			)
		)
	)
	(zone
		(layer "F.Cu")
		(hatch none 0.5)
		(connect_pads
			(clearance 0)
		)
		(min_thickness 0.25)
		(keepout
			(tracks allowed)
			(vias allowed)
			(pads allowed)
			(copperpour allowed)
			(footprints not_allowed)
		)
		(placement
			(enabled no)
			(sheetname "")
		)
		(fill
			(thermal_gap 0.5)
			(thermal_bridge_width 0.5)
			(island_removal_mode 0)
		)
		(polygon
			(pts
				(arc
					(start 254.124968 -360.764074)
					(mid 258.12496 -356.764082)
					(end 262.124952 -360.764074)
				)
				(arc
					(start 262.124952 -360.764074)
					(mid 258.12496 -364.764066)
					(end 254.124968 -360.764074)
				)
			)
		)
	)
	(zone
		(layer "F.Cu")
		(hatch none 0.5)
		(connect_pads
			(clearance 0)
		)
		(min_thickness 0.25)
		(keepout
			(tracks allowed)
			(vias allowed)
			(pads allowed)
			(copperpour allowed)
			(footprints allowed)
		)
		(placement
			(enabled no)
			(sheetname "")
		)
		(fill
			(thermal_gap 0.5)
			(thermal_bridge_width 0.5)
			(island_removal_mode 0)
		)
		(polygon
			(pts
				(xy 334.66024 -287.373568) (xy 334.94726 -287.373568) (xy 334.97774 -287.343088) (xy 334.97774 -286.715708)
				(xy 334.89138 -286.629348) (xy 334.70342 -286.629348) (xy 334.62976 -286.703008) (xy 334.62976 -287.343088)
			)
		)
	)
	(zone
		(layer "F.Cu")
		(hatch none 0.5)
		(connect_pads
			(clearance 0)
		)
		(min_thickness 0.25)
		(keepout
			(tracks allowed)
			(vias allowed)
			(pads allowed)
			(copperpour allowed)
			(footprints allowed)
		)
		(placement
			(enabled no)
			(sheetname "")
		)
		(fill
			(thermal_gap 0.5)
			(thermal_bridge_width 0.5)
			(island_removal_mode 0)
		)
		(polygon
			(pts
				(xy 192.066926 -308.126384) (xy 194.098926 -308.126384) (xy 194.098926 -308.354984) (xy 192.066926 -308.354984)
				(xy 191.930782 -308.354984) (xy 191.883792 -308.354984) (xy 191.883792 -308.126384) (xy 191.930782 -308.126384)
			)
		)
	)
	(zone
		(layer "F.Cu")
		(hatch none 0.5)
		(connect_pads
			(clearance 0)
		)
		(min_thickness 0.25)
		(keepout
			(tracks allowed)
			(vias allowed)
			(pads allowed)
			(copperpour allowed)
			(footprints allowed)
		)
		(placement
			(enabled no)
			(sheetname "")
		)
		(fill
			(thermal_gap 0.5)
			(thermal_bridge_width 0.5)
			(island_removal_mode 0)
		)
		(polygon
			(pts
				(xy 455.96556 -384.239008) (xy 455.96556 -381.935228) (xy 462.13014 -381.935228) (xy 462.13014 -384.239008)
			)
		)
	)
	(zone
		(layer "F.Cu")
		(hatch none 0.5)
		(connect_pads
			(clearance 0)
		)
		(min_thickness 0.25)
		(keepout
			(tracks not_allowed)
			(vias allowed)
			(pads allowed)
			(copperpour not_allowed)
			(footprints allowed)
		)
		(placement
			(enabled no)
			(sheetname "")
		)
		(fill
			(thermal_gap 0.5)
			(thermal_bridge_width 0.5)
			(island_removal_mode 0)
		)
		(polygon
			(pts
				(arc
					(start 233.849926 -192.499996)
					(mid 236.650022 -189.6999)
					(end 239.450118 -192.499996)
				)
				(arc
					(start 239.450118 -192.499996)
					(mid 236.650022 -195.300092)
					(end 233.849926 -192.499996)
				)
			)
		)
	)
	(zone
		(layer "F.Cu")
		(hatch none 0.5)
		(connect_pads
			(clearance 0)
		)
		(min_thickness 0.25)
		(keepout
			(tracks allowed)
			(vias allowed)
			(pads allowed)
			(copperpour allowed)
			(footprints allowed)
		)
		(placement
			(enabled no)
			(sheetname "")
		)
		(fill
			(thermal_gap 0.5)
			(thermal_bridge_width 0.5)
			(island_removal_mode 0)
		)
		(polygon
			(pts
				(xy 26.20391 -282.11653) (xy 26.20391 -281.672792) (xy 28.529026 -281.672792) (xy 28.529026 -282.11653)
			)
		)
	)
	(zone
		(layer "F.Cu")
		(hatch none 0.5)
		(connect_pads
			(clearance 0)
		)
		(min_thickness 0.25)
		(keepout
			(tracks allowed)
			(vias allowed)
			(pads allowed)
			(copperpour allowed)
			(footprints allowed)
		)
		(placement
			(enabled no)
			(sheetname "")
		)
		(fill
			(thermal_gap 0.5)
			(thermal_bridge_width 0.5)
			(island_removal_mode 0)
		)
		(polygon
			(pts
				(xy 443.450726 -295.604946) (xy 443.450726 -295.376346) (xy 445.482726 -295.376346) (xy 445.482726 -295.604946)
			)
		)
	)
	(zone
		(layer "F.Cu")
		(hatch none 0.5)
		(connect_pads
			(clearance 0)
		)
		(min_thickness 0.25)
		(keepout
			(tracks allowed)
			(vias allowed)
			(pads allowed)
			(copperpour allowed)
			(footprints allowed)
		)
		(placement
			(enabled no)
			(sheetname "")
		)
		(fill
			(thermal_gap 0.5)
			(thermal_bridge_width 0.5)
			(island_removal_mode 0)
		)
		(polygon
			(pts
				(xy 277.58771 -248.966482) (xy 277.58771 -248.522744) (xy 279.912826 -248.522744) (xy 279.912826 -248.966482)
			)
		)
	)
	(zone
		(layer "F.Cu")
		(hatch none 0.5)
		(connect_pads
			(clearance 0)
		)
		(min_thickness 0.25)
		(keepout
			(tracks allowed)
			(vias allowed)
			(pads allowed)
			(copperpour allowed)
			(footprints allowed)
		)
		(placement
			(enabled no)
			(sheetname "")
		)
		(fill
			(thermal_gap 0.5)
			(thermal_bridge_width 0.5)
			(island_removal_mode 0)
		)
		(polygon
			(pts
				(xy 87.9729 -216.842848) (xy 88.25992 -216.842848) (xy 88.2904 -216.812368) (xy 88.2904 -216.184988)
				(xy 88.20404 -216.098628) (xy 88.01608 -216.098628) (xy 87.94242 -216.172288) (xy 87.94242 -216.812368)
			)
		)
	)
	(zone
		(layer "F.Cu")
		(hatch none 0.5)
		(connect_pads
			(clearance 0)
		)
		(min_thickness 0.25)
		(keepout
			(tracks not_allowed)
			(vias allowed)
			(pads allowed)
			(copperpour not_allowed)
			(footprints allowed)
		)
		(placement
			(enabled no)
			(sheetname "")
		)
		(fill
			(thermal_gap 0.5)
			(thermal_bridge_width 0.5)
			(island_removal_mode 0)
		)
		(polygon
			(pts
				(xy 342.893142 -335.432908) (xy 343.10066 -335.432908) (xy 343.135458 -335.39811) (xy 343.135458 -334.373728)
				(xy 342.893142 -334.373728)
			)
		)
	)
	(zone
		(layer "F.Cu")
		(hatch none 0.5)
		(connect_pads
			(clearance 0)
		)
		(min_thickness 0.25)
		(keepout
			(tracks allowed)
			(vias allowed)
			(pads allowed)
			(copperpour allowed)
			(footprints not_allowed)
		)
		(placement
			(enabled no)
			(sheetname "")
		)
		(fill
			(thermal_gap 0.5)
			(thermal_bridge_width 0.5)
			(island_removal_mode 0)
		)
		(polygon
			(pts
				(arc
					(start 382.858772 -354.434902)
					(mid 384.458972 -352.834702)
					(end 386.058918 -354.434902)
				)
				(arc
					(start 386.058918 -354.434902)
					(mid 384.458972 -356.034848)
					(end 382.858772 -354.434902)
				)
			)
		)
	)
	(zone
		(layer "F.Cu")
		(hatch none 0.5)
		(connect_pads
			(clearance 0)
		)
		(min_thickness 0.25)
		(keepout
			(tracks allowed)
			(vias allowed)
			(pads allowed)
			(copperpour allowed)
			(footprints allowed)
		)
		(placement
			(enabled no)
			(sheetname "")
		)
		(fill
			(thermal_gap 0.5)
			(thermal_bridge_width 0.5)
			(island_removal_mode 0)
		)
		(polygon
			(pts
				(xy 297.54576 -413.64154) (xy 297.54576 -411.98546) (xy 299.1612 -411.98546) (xy 299.1612 -413.64154)
			)
		)
	)
	(zone
		(layer "F.Cu")
		(hatch none 0.5)
		(connect_pads
			(clearance 0)
		)
		(min_thickness 0.25)
		(keepout
			(tracks allowed)
			(vias allowed)
			(pads allowed)
			(copperpour allowed)
			(footprints allowed)
		)
		(placement
			(enabled no)
			(sheetname "")
		)
		(fill
			(thermal_gap 0.5)
			(thermal_bridge_width 0.5)
			(island_removal_mode 0)
		)
		(polygon
			(pts
				(xy 332.159356 -247.133872) (xy 332.362302 -247.336818) (xy 332.405228 -247.336818) (xy 332.848966 -246.893334)
				(xy 332.848966 -246.77116) (xy 332.716124 -246.638064) (xy 332.611984 -246.638064) (xy 332.159356 -247.090692)
			)
		)
	)
	(zone
		(layer "F.Cu")
		(hatch none 0.5)
		(connect_pads
			(clearance 0)
		)
		(min_thickness 0.25)
		(keepout
			(tracks allowed)
			(vias allowed)
			(pads allowed)
			(copperpour allowed)
			(footprints allowed)
		)
		(placement
			(enabled no)
			(sheetname "")
		)
		(fill
			(thermal_gap 0.5)
			(thermal_bridge_width 0.5)
			(island_removal_mode 0)
		)
		(polygon
			(pts
				(xy 352.171 -65.623948) (xy 352.171 -64.125348) (xy 351.36328 -64.125348) (xy 351.282 -64.206628)
				(xy 351.155 -64.333628) (xy 351.155 -65.496948) (xy 351.282 -65.623948)
			)
		)
	)
	(zone
		(layer "F.Cu")
		(hatch none 0.5)
		(connect_pads
			(clearance 0)
		)
		(min_thickness 0.25)
		(keepout
			(tracks allowed)
			(vias allowed)
			(pads allowed)
			(copperpour allowed)
			(footprints allowed)
		)
		(placement
			(enabled no)
			(sheetname "")
		)
		(fill
			(thermal_gap 0.5)
			(thermal_bridge_width 0.5)
			(island_removal_mode 0)
		)
		(polygon
			(pts
				(xy 11.11631 -305.066446) (xy 11.11631 -304.622708) (xy 13.441426 -304.622708) (xy 13.441426 -305.066446)
			)
		)
	)
	(zone
		(layer "F.Cu")
		(hatch none 0.5)
		(connect_pads
			(clearance 0)
		)
		(min_thickness 0.25)
		(keepout
			(tracks allowed)
			(vias allowed)
			(pads allowed)
			(copperpour allowed)
			(footprints allowed)
		)
		(placement
			(enabled no)
			(sheetname "")
		)
		(fill
			(thermal_gap 0.5)
			(thermal_bridge_width 0.5)
			(island_removal_mode 0)
		)
		(polygon
			(pts
				(xy 157.791658 -274.354798) (xy 157.791658 -274.126198) (xy 159.823658 -274.126198) (xy 159.823658 -274.354798)
			)
		)
	)
	(zone
		(layer "F.Cu")
		(hatch none 0.5)
		(connect_pads
			(clearance 0)
		)
		(min_thickness 0.25)
		(keepout
			(tracks allowed)
			(vias allowed)
			(pads allowed)
			(copperpour allowed)
			(footprints allowed)
		)
		(placement
			(enabled no)
			(sheetname "")
		)
		(fill
			(thermal_gap 0.5)
			(thermal_bridge_width 0.5)
			(island_removal_mode 0)
		)
		(polygon
			(pts
				(xy 90.4367 -289.006788) (xy 90.72372 -289.006788) (xy 90.7542 -288.976308) (xy 90.7542 -288.348928)
				(xy 90.66784 -288.262568) (xy 90.47988 -288.262568) (xy 90.40622 -288.336228) (xy 90.40622 -288.976308)
			)
		)
	)
	(zone
		(layer "F.Cu")
		(hatch none 0.5)
		(connect_pads
			(clearance 0)
		)
		(min_thickness 0.25)
		(keepout
			(tracks allowed)
			(vias allowed)
			(pads allowed)
			(copperpour allowed)
			(footprints allowed)
		)
		(placement
			(enabled no)
			(sheetname "")
		)
		(fill
			(thermal_gap 0.5)
			(thermal_bridge_width 0.5)
			(island_removal_mode 0)
		)
		(polygon
			(pts
				(xy 318.839342 -404.802594) (xy 318.839342 -399.959576) (xy 320.723768 -399.959576) (xy 320.723768 -404.802594)
			)
		)
	)
	(zone
		(layer "F.Cu")
		(hatch none 0.5)
		(connect_pads
			(clearance 0)
		)
		(min_thickness 0.25)
		(keepout
			(tracks allowed)
			(vias allowed)
			(pads allowed)
			(copperpour allowed)
			(footprints allowed)
		)
		(placement
			(enabled no)
			(sheetname "")
		)
		(fill
			(thermal_gap 0.5)
			(thermal_bridge_width 0.5)
			(island_removal_mode 0)
		)
		(polygon
			(pts
				(xy 29.647642 -308.46649) (xy 29.647642 -308.022752) (xy 31.972758 -308.022752) (xy 31.972758 -308.46649)
			)
		)
	)
	(zone
		(layer "F.Cu")
		(hatch none 0.5)
		(connect_pads
			(clearance 0)
		)
		(min_thickness 0.25)
		(keepout
			(tracks allowed)
			(vias allowed)
			(pads allowed)
			(copperpour allowed)
			(footprints not_allowed)
		)
		(placement
			(enabled no)
			(sheetname "")
		)
		(fill
			(thermal_gap 0.5)
			(thermal_bridge_width 0.5)
			(island_removal_mode 0)
		)
		(polygon
			(pts
				(xy 417.599876 -433.07) (xy 438.279286 -433.07) (xy 438.279286 -403.770084) (xy 421.779192 -403.770084)
				(xy 421.779192 -409.88996) (xy 415.279078 -409.88996) (xy 415.279078 -417.889944) (xy 417.599876 -417.889944)
			)
		)
	)
	(zone
		(layer "F.Cu")
		(hatch none 0.5)
		(connect_pads
			(clearance 0)
		)
		(min_thickness 0.25)
		(keepout
			(tracks allowed)
			(vias allowed)
			(pads allowed)
			(copperpour allowed)
			(footprints allowed)
		)
		(placement
			(enabled no)
			(sheetname "")
		)
		(fill
			(thermal_gap 0.5)
			(thermal_bridge_width 0.5)
			(island_removal_mode 0)
		)
		(polygon
			(pts
				(xy 432.02098 -184.821068) (xy 432.02098 -184.282588) (xy 433.3494 -184.282588) (xy 433.3494 -184.821068)
			)
		)
	)
	(zone
		(layer "F.Cu")
		(hatch none 0.5)
		(connect_pads
			(clearance 0)
		)
		(min_thickness 0.25)
		(keepout
			(tracks allowed)
			(vias allowed)
			(pads allowed)
			(copperpour allowed)
			(footprints allowed)
		)
		(placement
			(enabled no)
			(sheetname "")
		)
		(fill
			(thermal_gap 0.5)
			(thermal_bridge_width 0.5)
			(island_removal_mode 0)
		)
		(polygon
			(pts
				(xy 56.37911 -294.866568) (xy 56.37911 -294.42283) (xy 58.704226 -294.42283) (xy 58.704226 -294.866568)
			)
		)
	)
	(zone
		(layer "F.Cu")
		(hatch none 0.5)
		(connect_pads
			(clearance 0)
		)
		(min_thickness 0.25)
		(keepout
			(tracks allowed)
			(vias allowed)
			(pads allowed)
			(copperpour allowed)
			(footprints allowed)
		)
		(placement
			(enabled no)
			(sheetname "")
		)
		(fill
			(thermal_gap 0.5)
			(thermal_bridge_width 0.5)
			(island_removal_mode 0)
		)
		(polygon
			(pts
				(xy 374.029224 -404.802594) (xy 374.029224 -399.959576) (xy 375.91365 -399.959576) (xy 375.91365 -404.802594)
			)
		)
	)
	(zone
		(layer "F.Cu")
		(hatch none 0.5)
		(connect_pads
			(clearance 0)
		)
		(min_thickness 0.25)
		(keepout
			(tracks allowed)
			(vias allowed)
			(pads allowed)
			(copperpour allowed)
			(footprints allowed)
		)
		(placement
			(enabled no)
			(sheetname "")
		)
		(fill
			(thermal_gap 0.5)
			(thermal_bridge_width 0.5)
			(island_removal_mode 0)
		)
		(polygon
			(pts
				(xy 292.67531 -281.266646) (xy 292.67531 -280.822908) (xy 295.000426 -280.822908) (xy 295.000426 -281.266646)
			)
		)
	)
	(zone
		(layer "F.Cu")
		(hatch none 0.5)
		(connect_pads
			(clearance 0)
		)
		(min_thickness 0.25)
		(keepout
			(tracks allowed)
			(vias allowed)
			(pads allowed)
			(copperpour allowed)
			(footprints allowed)
		)
		(placement
			(enabled no)
			(sheetname "")
		)
		(fill
			(thermal_gap 0.5)
			(thermal_bridge_width 0.5)
			(island_removal_mode 0)
		)
		(polygon
			(pts
				(xy 289.231578 -235.36656) (xy 289.231578 -234.922822) (xy 291.556694 -234.922822) (xy 291.556694 -235.36656)
			)
		)
	)
	(zone
		(layer "F.Cu")
		(hatch none 0.5)
		(connect_pads
			(clearance 0)
		)
		(min_thickness 0.25)
		(keepout
			(tracks allowed)
			(vias allowed)
			(pads allowed)
			(copperpour allowed)
			(footprints allowed)
		)
		(placement
			(enabled no)
			(sheetname "")
		)
		(fill
			(thermal_gap 0.5)
			(thermal_bridge_width 0.5)
			(island_removal_mode 0)
		)
		(polygon
			(pts
				(xy 161.891726 -306.426362) (xy 163.923726 -306.426362) (xy 163.923726 -306.654962) (xy 161.891726 -306.654962)
				(xy 161.642298 -306.654962) (xy 161.642298 -306.426362)
			)
		)
	)
	(zone
		(layer "F.Cu")
		(hatch none 0.5)
		(connect_pads
			(clearance 0)
		)
		(min_thickness 0.25)
		(keepout
			(tracks allowed)
			(vias allowed)
			(pads allowed)
			(copperpour allowed)
			(footprints allowed)
		)
		(placement
			(enabled no)
			(sheetname "")
		)
		(fill
			(thermal_gap 0.5)
			(thermal_bridge_width 0.5)
			(island_removal_mode 0)
		)
		(polygon
			(pts
				(xy 383.54254 -330.164948) (xy 383.54254 -328.071988) (xy 385.47802 -328.071988) (xy 385.47802 -330.164948)
			)
		)
	)
	(zone
		(layer "F.Cu")
		(hatch none 0.5)
		(connect_pads
			(clearance 0)
		)
		(min_thickness 0.25)
		(keepout
			(tracks allowed)
			(vias allowed)
			(pads allowed)
			(copperpour allowed)
			(footprints allowed)
		)
		(placement
			(enabled no)
			(sheetname "")
		)
		(fill
			(thermal_gap 0.5)
			(thermal_bridge_width 0.5)
			(island_removal_mode 0)
		)
		(polygon
			(pts
				(xy 176.979326 -225.67646) (xy 179.011326 -225.67646) (xy 179.011326 -225.90506) (xy 176.979326 -225.90506)
				(xy 176.843182 -225.90506) (xy 176.796192 -225.90506) (xy 176.796192 -225.67646) (xy 176.843182 -225.67646)
			)
		)
	)
	(zone
		(layer "F.Cu")
		(hatch none 0.5)
		(connect_pads
			(clearance 0)
		)
		(min_thickness 0.25)
		(keepout
			(tracks allowed)
			(vias allowed)
			(pads allowed)
			(copperpour allowed)
			(footprints allowed)
		)
		(placement
			(enabled no)
			(sheetname "")
		)
		(fill
			(thermal_gap 0.5)
			(thermal_bridge_width 0.5)
			(island_removal_mode 0)
		)
		(polygon
			(pts
				(xy 210.598258 -216.554812) (xy 210.598258 -216.326212) (xy 212.630258 -216.326212) (xy 212.630258 -216.554812)
			)
		)
	)
	(zone
		(layer "F.Cu")
		(hatch none 0.5)
		(connect_pads
			(clearance 0)
		)
		(min_thickness 0.25)
		(keepout
			(tracks not_allowed)
			(vias allowed)
			(pads allowed)
			(copperpour not_allowed)
			(footprints allowed)
		)
		(placement
			(enabled no)
			(sheetname "")
		)
		(fill
			(thermal_gap 0.5)
			(thermal_bridge_width 0.5)
			(island_removal_mode 0)
		)
		(polygon
			(pts
				(xy 415.923222 -171.77258) (xy 415.260282 -171.77258) (xy 415.260282 -173.32198) (xy 415.716974 -173.32198)
				(xy 415.716974 -172.626274) (xy 415.556446 -172.626274) (xy 415.556446 -172.067474) (xy 415.962846 -172.067474)
				(xy 415.962846 -172.626274) (xy 415.742374 -172.626274) (xy 415.742374 -173.32198) (xy 415.869374 -173.32198)
				(xy 415.869374 -172.866304) (xy 416.342322 -172.866304) (xy 416.342322 -172.623988) (xy 416.255962 -172.623988)
				(xy 416.255962 -172.02404) (xy 415.923222 -172.02404)
			)
		)
	)
	(zone
		(layer "F.Cu")
		(hatch none 0.5)
		(connect_pads
			(clearance 0)
		)
		(min_thickness 0.25)
		(keepout
			(tracks allowed)
			(vias allowed)
			(pads allowed)
			(copperpour allowed)
			(footprints allowed)
		)
		(placement
			(enabled no)
			(sheetname "")
		)
		(fill
			(thermal_gap 0.5)
			(thermal_bridge_width 0.5)
			(island_removal_mode 0)
		)
		(polygon
			(pts
				(xy 428.363126 -299.00499) (xy 428.363126 -298.77639) (xy 430.395126 -298.77639) (xy 430.395126 -299.00499)
			)
		)
	)
	(zone
		(layer "F.Cu")
		(hatch none 0.5)
		(connect_pads
			(clearance 0)
		)
		(min_thickness 0.25)
		(keepout
			(tracks allowed)
			(vias allowed)
			(pads allowed)
			(copperpour allowed)
			(footprints allowed)
		)
		(placement
			(enabled no)
			(sheetname "")
		)
		(fill
			(thermal_gap 0.5)
			(thermal_bridge_width 0.5)
			(island_removal_mode 0)
		)
		(polygon
			(pts
				(xy 63.977012 -203.06665) (xy 63.977012 -202.622912) (xy 66.212212 -202.622912) (xy 66.212212 -203.06665)
			)
		)
	)
	(zone
		(layer "F.Cu")
		(hatch none 0.5)
		(connect_pads
			(clearance 0)
		)
		(min_thickness 0.25)
		(keepout
			(tracks allowed)
			(vias allowed)
			(pads allowed)
			(copperpour allowed)
			(footprints allowed)
		)
		(placement
			(enabled no)
			(sheetname "")
		)
		(fill
			(thermal_gap 0.5)
			(thermal_bridge_width 0.5)
			(island_removal_mode 0)
		)
		(polygon
			(pts
				(xy 413.275526 -214.85479) (xy 413.275526 -214.62619) (xy 415.307526 -214.62619) (xy 415.307526 -214.85479)
			)
		)
	)
	(zone
		(layer "F.Cu")
		(hatch none 0.5)
		(connect_pads
			(clearance 0)
		)
		(min_thickness 0.25)
		(keepout
			(tracks allowed)
			(vias allowed)
			(pads allowed)
			(copperpour allowed)
			(footprints allowed)
		)
		(placement
			(enabled no)
			(sheetname "")
		)
		(fill
			(thermal_gap 0.5)
			(thermal_bridge_width 0.5)
			(island_removal_mode 0)
		)
		(polygon
			(pts
				(xy 292.67531 -230.266494) (xy 292.67531 -229.822756) (xy 295.000426 -229.822756) (xy 295.000426 -230.266494)
			)
		)
	)
	(zone
		(layer "F.Cu")
		(hatch none 0.5)
		(connect_pads
			(clearance 0)
		)
		(min_thickness 0.25)
		(keepout
			(tracks allowed)
			(vias allowed)
			(pads allowed)
			(copperpour allowed)
			(footprints allowed)
		)
		(placement
			(enabled no)
			(sheetname "")
		)
		(fill
			(thermal_gap 0.5)
			(thermal_bridge_width 0.5)
			(island_removal_mode 0)
		)
		(polygon
			(pts
				(xy 54.25186 -6.111748) (xy 54.25186 -3.904488) (xy 57.01792 -3.904488) (xy 57.01792 -6.111748)
			)
		)
	)
	(zone
		(layer "F.Cu")
		(hatch none 0.5)
		(connect_pads
			(clearance 0)
		)
		(min_thickness 0.25)
		(keepout
			(tracks not_allowed)
			(vias allowed)
			(pads allowed)
			(copperpour not_allowed)
			(footprints allowed)
		)
		(placement
			(enabled no)
			(sheetname "")
		)
		(fill
			(thermal_gap 0.5)
			(thermal_bridge_width 0.5)
			(island_removal_mode 0)
		)
		(polygon
			(pts
				(arc
					(start 177.749962 -435.59984)
					(mid 179.749958 -433.599844)
					(end 181.749954 -435.59984)
				)
				(arc
					(start 181.749954 -435.59984)
					(mid 179.749958 -437.599836)
					(end 177.749962 -435.59984)
				)
			)
		)
	)
	(zone
		(layer "F.Cu")
		(hatch none 0.5)
		(connect_pads
			(clearance 0)
		)
		(min_thickness 0.25)
		(keepout
			(tracks allowed)
			(vias allowed)
			(pads allowed)
			(copperpour allowed)
			(footprints allowed)
		)
		(placement
			(enabled no)
			(sheetname "")
		)
		(fill
			(thermal_gap 0.5)
			(thermal_bridge_width 0.5)
			(island_removal_mode 0)
		)
		(polygon
			(pts
				(xy 161.891726 -284.55493) (xy 161.891726 -284.32633) (xy 163.923726 -284.32633) (xy 163.923726 -284.55493)
			)
		)
	)
	(zone
		(layer "F.Cu")
		(hatch none 0.5)
		(connect_pads
			(clearance 0)
		)
		(min_thickness 0.25)
		(keepout
			(tracks allowed)
			(vias allowed)
			(pads allowed)
			(copperpour allowed)
			(footprints allowed)
		)
		(placement
			(enabled no)
			(sheetname "")
		)
		(fill
			(thermal_gap 0.5)
			(thermal_bridge_width 0.5)
			(island_removal_mode 0)
		)
		(polygon
			(pts
				(xy 455.094594 -206.976472) (xy 457.126594 -206.976472) (xy 457.126594 -207.205072) (xy 455.094594 -207.205072)
				(xy 454.95845 -207.205072) (xy 454.91146 -207.205072) (xy 454.91146 -206.976472) (xy 454.95845 -206.976472)
			)
		)
	)
	(zone
		(layer "F.Cu")
		(hatch none 0.5)
		(connect_pads
			(clearance 0)
		)
		(min_thickness 0.25)
		(keepout
			(tracks allowed)
			(vias allowed)
			(pads allowed)
			(copperpour allowed)
			(footprints allowed)
		)
		(placement
			(enabled no)
			(sheetname "")
		)
		(fill
			(thermal_gap 0.5)
			(thermal_bridge_width 0.5)
			(island_removal_mode 0)
		)
		(polygon
			(pts
				(xy 165.335458 -225.904806) (xy 165.335458 -225.676206) (xy 167.367458 -225.676206) (xy 167.367458 -225.904806)
			)
		)
	)
	(zone
		(layer "F.Cu")
		(hatch none 0.5)
		(connect_pads
			(clearance 0)
		)
		(min_thickness 0.25)
		(keepout
			(tracks allowed)
			(vias allowed)
			(pads allowed)
			(copperpour allowed)
			(footprints allowed)
		)
		(placement
			(enabled no)
			(sheetname "")
		)
		(fill
			(thermal_gap 0.5)
			(thermal_bridge_width 0.5)
			(island_removal_mode 0)
		)
		(polygon
			(pts
				(xy 165.335458 -250.554998) (xy 165.335458 -250.326398) (xy 167.367458 -250.326398) (xy 167.367458 -250.554998)
			)
		)
	)
	(zone
		(layer "F.Cu")
		(hatch none 0.5)
		(connect_pads
			(clearance 0)
		)
		(min_thickness 0.25)
		(keepout
			(tracks allowed)
			(vias allowed)
			(pads allowed)
			(copperpour allowed)
			(footprints not_allowed)
		)
		(placement
			(enabled no)
			(sheetname "")
		)
		(fill
			(thermal_gap 0.5)
			(thermal_bridge_width 0.5)
			(island_removal_mode 0)
		)
		(polygon
			(pts
				(xy 364.16488 -237.00994) (xy 364.16488 -261.62) (xy 367.795048 -261.62) (xy 367.795048 -237.00994)
			)
		)
	)
	(zone
		(layer "F.Cu")
		(hatch none 0.5)
		(connect_pads
			(clearance 0)
		)
		(min_thickness 0.25)
		(keepout
			(tracks allowed)
			(vias allowed)
			(pads allowed)
			(copperpour allowed)
			(footprints allowed)
		)
		(placement
			(enabled no)
			(sheetname "")
		)
		(fill
			(thermal_gap 0.5)
			(thermal_bridge_width 0.5)
			(island_removal_mode 0)
		)
		(polygon
			(pts
				(xy 424.919394 -297.076368) (xy 426.951394 -297.076368) (xy 426.951394 -297.304968) (xy 424.919394 -297.304968)
				(xy 424.78325 -297.304968) (xy 424.73626 -297.304968) (xy 424.73626 -297.076368) (xy 424.78325 -297.076368)
			)
		)
	)
	(zone
		(layer "F.Cu")
		(hatch none 0.5)
		(connect_pads
			(clearance 0)
		)
		(min_thickness 0.25)
		(keepout
			(tracks allowed)
			(vias allowed)
			(pads allowed)
			(copperpour allowed)
			(footprints allowed)
		)
		(placement
			(enabled no)
			(sheetname "")
		)
		(fill
			(thermal_gap 0.5)
			(thermal_bridge_width 0.5)
			(island_removal_mode 0)
		)
		(polygon
			(pts
				(xy 307.76291 -216.666572) (xy 307.76291 -216.222834) (xy 310.088026 -216.222834) (xy 310.088026 -216.666572)
			)
		)
	)
	(zone
		(layer "F.Cu")
		(hatch none 0.5)
		(connect_pads
			(clearance 0)
		)
		(min_thickness 0.25)
		(keepout
			(tracks allowed)
			(vias allowed)
			(pads allowed)
			(copperpour allowed)
			(footprints allowed)
		)
		(placement
			(enabled no)
			(sheetname "")
		)
		(fill
			(thermal_gap 0.5)
			(thermal_bridge_width 0.5)
			(island_removal_mode 0)
		)
		(polygon
			(pts
				(xy 41.29151 -205.616556) (xy 41.29151 -205.172818) (xy 43.616626 -205.172818) (xy 43.616626 -205.616556)
			)
		)
	)
	(zone
		(layer "F.Cu")
		(hatch none 0.5)
		(connect_pads
			(clearance 0)
		)
		(min_thickness 0.25)
		(keepout
			(tracks allowed)
			(vias allowed)
			(pads allowed)
			(copperpour allowed)
			(footprints not_allowed)
		)
		(placement
			(enabled no)
			(sheetname "")
		)
		(fill
			(thermal_gap 0.5)
			(thermal_bridge_width 0.5)
			(island_removal_mode 0)
		)
		(polygon
			(pts
				(xy 451.01637 -330.091796) (xy 457.11618 -330.091796) (xy 457.11618 -186.09183) (xy 451.01637 -186.09183)
			)
		)
	)
	(zone
		(layer "F.Cu")
		(hatch none 0.5)
		(connect_pads
			(clearance 0)
		)
		(min_thickness 0.25)
		(keepout
			(tracks allowed)
			(vias allowed)
			(pads allowed)
			(copperpour allowed)
			(footprints not_allowed)
		)
		(placement
			(enabled no)
			(sheetname "")
		)
		(fill
			(thermal_gap 0.5)
			(thermal_bridge_width 0.5)
			(island_removal_mode 0)
		)
		(polygon
			(pts
				(xy 304.47996 -410.77007) (xy 415.279078 -410.77007) (xy 415.279078 -409.88996) (xy 421.779192 -409.88996)
				(xy 421.779192 -403.770084) (xy 437.279034 -403.770084) (xy 437.279034 -398.75587) (xy 467.300056 -398.75587)
				(xy 467.300056 -374.753886) (xy 449.279518 -374.753886) (xy 449.279518 -355.769672) (xy 390.488678 -355.763576)
				(xy 390.488678 -363.21492) (xy 378.420884 -363.21492) (xy 378.420884 -355.763576) (xy 335.848706 -355.763576)
				(xy 335.848706 -363.21492) (xy 323.864986 -363.21492) (xy 323.864986 -355.76383) (xy 270.480028 -355.76383)
				(xy 270.47825 -374.753886) (xy 249.879866 -374.753886) (xy 249.879866 -398.75587) (xy 281.480006 -398.75587)
				(xy 281.480006 -382.770126) (xy 304.47996 -382.770126)
			)
		)
	)
	(zone
		(layer "F.Cu")
		(hatch none 0.5)
		(connect_pads
			(clearance 0)
		)
		(min_thickness 0.25)
		(keepout
			(tracks allowed)
			(vias allowed)
			(pads allowed)
			(copperpour allowed)
			(footprints allowed)
		)
		(placement
			(enabled no)
			(sheetname "")
		)
		(fill
			(thermal_gap 0.5)
			(thermal_bridge_width 0.5)
			(island_removal_mode 0)
		)
		(polygon
			(pts
				(xy 443.450726 -230.154988) (xy 443.450726 -229.926388) (xy 445.482726 -229.926388) (xy 445.482726 -230.154988)
			)
		)
	)
	(zone
		(layer "F.Cu")
		(hatch none 0.5)
		(connect_pads
			(clearance 0)
		)
		(min_thickness 0.25)
		(keepout
			(tracks allowed)
			(vias allowed)
			(pads allowed)
			(copperpour allowed)
			(footprints not_allowed)
		)
		(placement
			(enabled no)
			(sheetname "")
		)
		(fill
			(thermal_gap 0.5)
			(thermal_bridge_width 0.5)
			(island_removal_mode 0)
		)
		(polygon
			(pts
				(arc
					(start 113.609882 -431.360072)
					(mid 112.024922 -432.945032)
					(end 110.439962 -431.360072)
				)
				(arc
					(start 110.439962 -431.360072)
					(mid 112.024922 -429.775112)
					(end 113.609882 -431.360072)
				)
			)
		)
	)
	(zone
		(layer "F.Cu")
		(hatch none 0.5)
		(connect_pads
			(clearance 0)
		)
		(min_thickness 0.25)
		(keepout
			(tracks not_allowed)
			(vias allowed)
			(pads allowed)
			(copperpour not_allowed)
			(footprints allowed)
		)
		(placement
			(enabled no)
			(sheetname "")
		)
		(fill
			(thermal_gap 0.5)
			(thermal_bridge_width 0.5)
			(island_removal_mode 0)
		)
		(polygon
			(pts
				(arc
					(start 238.949992 -39.424864)
					(mid 239.94999 -38.424866)
					(end 240.949988 -39.424864)
				)
				(arc
					(start 240.949988 -39.424864)
					(mid 239.94999 -40.424862)
					(end 238.949992 -39.424864)
				)
			)
		)
	)
	(zone
		(layer "F.Cu")
		(hatch none 0.5)
		(connect_pads
			(clearance 0)
		)
		(min_thickness 0.25)
		(keepout
			(tracks allowed)
			(vias allowed)
			(pads allowed)
			(copperpour allowed)
			(footprints allowed)
		)
		(placement
			(enabled no)
			(sheetname "")
		)
		(fill
			(thermal_gap 0.5)
			(thermal_bridge_width 0.5)
			(island_removal_mode 0)
		)
		(polygon
			(pts
				(xy 61.122052 -410.948886) (xy 61.122052 -406.105868) (xy 63.006478 -406.105868) (xy 63.006478 -410.948886)
			)
		)
	)
	(zone
		(layer "F.Cu")
		(hatch none 0.5)
		(connect_pads
			(clearance 0)
		)
		(min_thickness 0.25)
		(keepout
			(tracks not_allowed)
			(vias allowed)
			(pads allowed)
			(copperpour not_allowed)
			(footprints allowed)
		)
		(placement
			(enabled no)
			(sheetname "")
		)
		(fill
			(thermal_gap 0.5)
			(thermal_bridge_width 0.5)
			(island_removal_mode 0)
		)
		(polygon
			(pts
				(arc
					(start 7.53999 -160.50006)
					(mid 10.340086 -157.699964)
					(end 13.139928 -160.50006)
				)
				(arc
					(start 13.139928 -160.50006)
					(mid 10.340086 -163.299902)
					(end 7.53999 -160.50006)
				)
			)
		)
	)
	(zone
		(layer "F.Cu")
		(hatch none 0.5)
		(connect_pads
			(clearance 0)
		)
		(min_thickness 0.25)
		(keepout
			(tracks allowed)
			(vias allowed)
			(pads allowed)
			(copperpour allowed)
			(footprints not_allowed)
		)
		(placement
			(enabled no)
			(sheetname "")
		)
		(fill
			(thermal_gap 0.5)
			(thermal_bridge_width 0.5)
			(island_removal_mode 0)
		)
		(polygon
			(pts
				(arc
					(start 231.650032 -272.50009)
					(mid 236.650022 -267.5001)
					(end 241.650012 -272.50009)
				)
				(arc
					(start 241.650012 -272.50009)
					(mid 236.650022 -277.50008)
					(end 231.650032 -272.50009)
				)
			)
		)
	)
	(zone
		(layer "F.Cu")
		(hatch none 0.5)
		(connect_pads
			(clearance 0)
		)
		(min_thickness 0.25)
		(keepout
			(tracks allowed)
			(vias allowed)
			(pads allowed)
			(copperpour allowed)
			(footprints allowed)
		)
		(placement
			(enabled no)
			(sheetname "")
		)
		(fill
			(thermal_gap 0.5)
			(thermal_bridge_width 0.5)
			(island_removal_mode 0)
		)
		(polygon
			(pts
				(xy 14.560042 -314.41644) (xy 14.560042 -313.972702) (xy 16.885158 -313.972702) (xy 16.885158 -314.41644)
			)
		)
	)
	(zone
		(layer "F.Cu")
		(hatch none 0.5)
		(connect_pads
			(clearance 0)
		)
		(min_thickness 0.25)
		(keepout
			(tracks allowed)
			(vias allowed)
			(pads allowed)
			(copperpour allowed)
			(footprints allowed)
		)
		(placement
			(enabled no)
			(sheetname "")
		)
		(fill
			(thermal_gap 0.5)
			(thermal_bridge_width 0.5)
			(island_removal_mode 0)
		)
		(polygon
			(pts
				(xy 192.066926 -197.626478) (xy 194.098926 -197.626478) (xy 194.098926 -197.855078) (xy 192.066926 -197.855078)
				(xy 191.930782 -197.855078) (xy 191.883792 -197.855078) (xy 191.883792 -197.626478) (xy 191.930782 -197.626478)
			)
		)
	)
	(zone
		(layer "F.Cu")
		(hatch none 0.5)
		(connect_pads
			(clearance 0)
		)
		(min_thickness 0.25)
		(keepout
			(tracks allowed)
			(vias allowed)
			(pads allowed)
			(copperpour allowed)
			(footprints allowed)
		)
		(placement
			(enabled no)
			(sheetname "")
		)
		(fill
			(thermal_gap 0.5)
			(thermal_bridge_width 0.5)
			(island_removal_mode 0)
		)
		(polygon
			(pts
				(xy 207.154526 -263.076436) (xy 209.186526 -263.076436) (xy 209.186526 -263.305036) (xy 207.154526 -263.305036)
				(xy 206.987902 -263.305036) (xy 206.987902 -263.076436)
			)
		)
	)
	(zone
		(layer "F.Cu")
		(hatch none 0.5)
		(connect_pads
			(clearance 0)
		)
		(min_thickness 0.25)
		(keepout
			(tracks allowed)
			(vias allowed)
			(pads allowed)
			(copperpour allowed)
			(footprints allowed)
		)
		(placement
			(enabled no)
			(sheetname "")
		)
		(fill
			(thermal_gap 0.5)
			(thermal_bridge_width 0.5)
			(island_removal_mode 0)
		)
		(polygon
			(pts
				(xy 277.58771 -299.116496) (xy 277.58771 -298.672758) (xy 279.912826 -298.672758) (xy 279.912826 -299.116496)
			)
		)
	)
	(zone
		(layer "F.Cu")
		(hatch none 0.5)
		(connect_pads
			(clearance 0)
		)
		(min_thickness 0.25)
		(keepout
			(tracks allowed)
			(vias allowed)
			(pads allowed)
			(copperpour allowed)
			(footprints allowed)
		)
		(placement
			(enabled no)
			(sheetname "")
		)
		(fill
			(thermal_gap 0.5)
			(thermal_bridge_width 0.5)
			(island_removal_mode 0)
		)
		(polygon
			(pts
				(xy 304.319178 -265.966448) (xy 304.319178 -265.52271) (xy 306.644294 -265.52271) (xy 306.644294 -265.966448)
			)
		)
	)
	(zone
		(layer "F.Cu")
		(hatch none 0.5)
		(connect_pads
			(clearance 0)
		)
		(min_thickness 0.25)
		(keepout
			(tracks allowed)
			(vias allowed)
			(pads allowed)
			(copperpour allowed)
			(footprints allowed)
		)
		(placement
			(enabled no)
			(sheetname "")
		)
		(fill
			(thermal_gap 0.5)
			(thermal_bridge_width 0.5)
			(island_removal_mode 0)
		)
		(polygon
			(pts
				(xy 249.34164 -95.534988) (xy 249.34164 -94.409768) (xy 250.52528 -94.409768) (xy 250.52528 -95.534988)
			)
		)
	)
	(zone
		(layer "F.Cu")
		(hatch none 0.5)
		(connect_pads
			(clearance 0)
		)
		(min_thickness 0.25)
		(keepout
			(tracks allowed)
			(vias allowed)
			(pads allowed)
			(copperpour allowed)
			(footprints allowed)
		)
		(placement
			(enabled no)
			(sheetname "")
		)
		(fill
			(thermal_gap 0.5)
			(thermal_bridge_width 0.5)
			(island_removal_mode 0)
		)
		(polygon
			(pts
				(xy 277.58771 -205.616556) (xy 277.58771 -205.172818) (xy 279.912826 -205.172818) (xy 279.912826 -205.616556)
			)
		)
	)
	(zone
		(layer "F.Cu")
		(hatch none 0.5)
		(connect_pads
			(clearance 0)
		)
		(min_thickness 0.25)
		(keepout
			(tracks allowed)
			(vias allowed)
			(pads allowed)
			(copperpour allowed)
			(footprints allowed)
		)
		(placement
			(enabled no)
			(sheetname "")
		)
		(fill
			(thermal_gap 0.5)
			(thermal_bridge_width 0.5)
			(island_removal_mode 0)
		)
		(polygon
			(pts
				(xy 346.408502 -404.802594) (xy 346.408502 -399.959576) (xy 348.292928 -399.959576) (xy 348.292928 -404.802594)
			)
		)
	)
	(zone
		(layer "F.Cu")
		(hatch none 0.5)
		(connect_pads
			(clearance 0)
		)
		(min_thickness 0.25)
		(keepout
			(tracks allowed)
			(vias allowed)
			(pads allowed)
			(copperpour allowed)
			(footprints allowed)
		)
		(placement
			(enabled no)
			(sheetname "")
		)
		(fill
			(thermal_gap 0.5)
			(thermal_bridge_width 0.5)
			(island_removal_mode 0)
		)
		(polygon
			(pts
				(xy 207.154526 -276.676358) (xy 209.186526 -276.676358) (xy 209.186526 -276.904958) (xy 207.154526 -276.904958)
				(xy 207.018382 -276.904958) (xy 206.971392 -276.904958) (xy 206.971392 -276.676358) (xy 207.018382 -276.676358)
			)
		)
	)
	(zone
		(layer "F.Cu")
		(hatch none 0.5)
		(connect_pads
			(clearance 0)
		)
		(min_thickness 0.25)
		(keepout
			(tracks allowed)
			(vias allowed)
			(pads allowed)
			(copperpour allowed)
			(footprints allowed)
		)
		(placement
			(enabled no)
			(sheetname "")
		)
		(fill
			(thermal_gap 0.5)
			(thermal_bridge_width 0.5)
			(island_removal_mode 0)
		)
		(polygon
			(pts
				(xy 59.822842 -269.366492) (xy 59.822842 -268.922754) (xy 62.147958 -268.922754) (xy 62.147958 -269.366492)
			)
		)
	)
	(zone
		(layer "F.Cu")
		(hatch none 0.5)
		(connect_pads
			(clearance 0)
		)
		(min_thickness 0.25)
		(keepout
			(tracks allowed)
			(vias allowed)
			(pads allowed)
			(copperpour allowed)
			(footprints allowed)
		)
		(placement
			(enabled no)
			(sheetname "")
		)
		(fill
			(thermal_gap 0.5)
			(thermal_bridge_width 0.5)
			(island_removal_mode 0)
		)
		(polygon
			(pts
				(xy 405.731726 -207.204818) (xy 405.731726 -206.976218) (xy 407.763726 -206.976218) (xy 407.763726 -207.204818)
			)
		)
	)
	(zone
		(layer "F.Cu")
		(hatch none 0.5)
		(connect_pads
			(clearance 0)
		)
		(min_thickness 0.25)
		(keepout
			(tracks allowed)
			(vias allowed)
			(pads allowed)
			(copperpour allowed)
			(footprints allowed)
		)
		(placement
			(enabled no)
			(sheetname "")
		)
		(fill
			(thermal_gap 0.5)
			(thermal_bridge_width 0.5)
			(island_removal_mode 0)
		)
		(polygon
			(pts
				(xy 455.094594 -220.576394) (xy 457.126594 -220.576394) (xy 457.126594 -220.804994) (xy 455.094594 -220.804994)
				(xy 454.95845 -220.804994) (xy 454.91146 -220.804994) (xy 454.91146 -220.576394) (xy 454.95845 -220.576394)
			)
		)
	)
	(zone
		(layer "F.Cu")
		(hatch none 0.5)
		(connect_pads
			(clearance 0)
		)
		(min_thickness 0.25)
		(keepout
			(tracks allowed)
			(vias allowed)
			(pads allowed)
			(copperpour allowed)
			(footprints allowed)
		)
		(placement
			(enabled no)
			(sheetname "")
		)
		(fill
			(thermal_gap 0.5)
			(thermal_bridge_width 0.5)
			(island_removal_mode 0)
		)
		(polygon
			(pts
				(xy 24.71166 -129.845308) (xy 24.71166 -133.764528) (xy 26.43124 -135.484108) (xy 30.67812 -135.484108)
				(xy 30.70225 -135.459978) (xy 32.76346 -137.521188) (xy 34.12744 -137.521188) (xy 36.34232 -135.306308)
				(xy 36.34232 -133.292088) (xy 36.8554 -132.779008) (xy 36.8554 -131.656328) (xy 36.34232 -131.143248)
				(xy 36.34232 -130.528568) (xy 38.43528 -128.435608) (xy 38.43528 -127.089408) (xy 36.95954 -125.613668)
				(xy 29.5783 -125.613668) (xy 29.13888 -125.174248) (xy 26.76144 -125.174248) (xy 26.76144 -126.474728)
				(xy 27.39898 -127.112268) (xy 27.39898 -129.029968) (xy 26.58364 -129.845308)
			)
		)
	)
	(zone
		(layer "F.Cu")
		(hatch none 0.5)
		(connect_pads
			(clearance 0)
		)
		(min_thickness 0.25)
		(keepout
			(tracks allowed)
			(vias allowed)
			(pads allowed)
			(copperpour allowed)
			(footprints allowed)
		)
		(placement
			(enabled no)
			(sheetname "")
		)
		(fill
			(thermal_gap 0.5)
			(thermal_bridge_width 0.5)
			(island_removal_mode 0)
		)
		(polygon
			(pts
				(xy 259.056378 -237.916466) (xy 259.056378 -237.472728) (xy 261.381494 -237.472728) (xy 261.381494 -237.916466)
			)
		)
	)
	(zone
		(layer "F.Cu")
		(hatch none 0.5)
		(connect_pads
			(clearance 0)
		)
		(min_thickness 0.25)
		(keepout
			(tracks allowed)
			(vias allowed)
			(pads allowed)
			(copperpour allowed)
			(footprints allowed)
		)
		(placement
			(enabled no)
			(sheetname "")
		)
		(fill
			(thermal_gap 0.5)
			(thermal_bridge_width 0.5)
			(island_removal_mode 0)
		)
		(polygon
			(pts
				(xy 176.979326 -309.826406) (xy 179.011326 -309.826406) (xy 179.011326 -310.055006) (xy 176.979326 -310.055006)
				(xy 176.843182 -310.055006) (xy 176.796192 -310.055006) (xy 176.796192 -309.826406) (xy 176.843182 -309.826406)
			)
		)
	)
	(zone
		(layer "F.Cu")
		(hatch none 0.5)
		(connect_pads
			(clearance 0)
		)
		(min_thickness 0.25)
		(keepout
			(tracks allowed)
			(vias allowed)
			(pads allowed)
			(copperpour allowed)
			(footprints allowed)
		)
		(placement
			(enabled no)
			(sheetname "")
		)
		(fill
			(thermal_gap 0.5)
			(thermal_bridge_width 0.5)
			(island_removal_mode 0)
		)
		(polygon
			(pts
				(xy 210.598258 -300.705012) (xy 210.598258 -300.476412) (xy 212.630258 -300.476412) (xy 212.630258 -300.705012)
			)
		)
	)
	(zone
		(layer "F.Cu")
		(hatch none 0.5)
		(connect_pads
			(clearance 0)
		)
		(min_thickness 0.25)
		(keepout
			(tracks allowed)
			(vias allowed)
			(pads allowed)
			(copperpour allowed)
			(footprints allowed)
		)
		(placement
			(enabled no)
			(sheetname "")
		)
		(fill
			(thermal_gap 0.5)
			(thermal_bridge_width 0.5)
			(island_removal_mode 0)
		)
		(polygon
			(pts
				(xy 11.11631 -228.566472) (xy 11.11631 -228.122734) (xy 13.441426 -228.122734) (xy 13.441426 -228.566472)
			)
		)
	)
	(zone
		(layer "F.Cu")
		(hatch none 0.5)
		(connect_pads
			(clearance 0)
		)
		(min_thickness 0.25)
		(keepout
			(tracks not_allowed)
			(vias allowed)
			(pads allowed)
			(copperpour not_allowed)
			(footprints allowed)
		)
		(placement
			(enabled no)
			(sheetname "")
		)
		(fill
			(thermal_gap 0.5)
			(thermal_bridge_width 0.5)
			(island_removal_mode 0)
		)
		(polygon
			(pts
				(arc
					(start 92.099892 -22.29993)
					(mid 94.899988 -19.499834)
					(end 97.700084 -22.29993)
				)
				(arc
					(start 97.700084 -22.29993)
					(mid 94.899988 -25.100026)
					(end 92.099892 -22.29993)
				)
			)
		)
	)
	(zone
		(layer "F.Cu")
		(hatch none 0.5)
		(connect_pads
			(clearance 0)
		)
		(min_thickness 0.25)
		(keepout
			(tracks allowed)
			(vias allowed)
			(pads allowed)
			(copperpour allowed)
			(footprints allowed)
		)
		(placement
			(enabled no)
			(sheetname "")
		)
		(fill
			(thermal_gap 0.5)
			(thermal_bridge_width 0.5)
			(island_removal_mode 0)
		)
		(polygon
			(pts
				(xy 458.538326 -239.504982) (xy 458.538326 -239.276382) (xy 460.570326 -239.276382) (xy 460.570326 -239.504982)
			)
		)
	)
	(zone
		(layer "F.Cu")
		(hatch none 0.5)
		(connect_pads
			(clearance 0)
		)
		(min_thickness 0.25)
		(keepout
			(tracks allowed)
			(vias allowed)
			(pads allowed)
			(copperpour allowed)
			(footprints allowed)
		)
		(placement
			(enabled no)
			(sheetname "")
		)
		(fill
			(thermal_gap 0.5)
			(thermal_bridge_width 0.5)
			(island_removal_mode 0)
		)
		(polygon
			(pts
				(xy 56.37911 -285.516574) (xy 56.37911 -285.072836) (xy 58.704226 -285.072836) (xy 58.704226 -285.516574)
			)
		)
	)
	(zone
		(layer "F.Cu")
		(hatch none 0.5)
		(connect_pads
			(clearance 0)
		)
		(min_thickness 0.25)
		(keepout
			(tracks allowed)
			(vias allowed)
			(pads allowed)
			(copperpour allowed)
			(footprints allowed)
		)
		(placement
			(enabled no)
			(sheetname "")
		)
		(fill
			(thermal_gap 0.5)
			(thermal_bridge_width 0.5)
			(island_removal_mode 0)
		)
		(polygon
			(pts
				(xy 176.979326 -209.75701) (xy 179.011326 -209.75701) (xy 179.011326 -209.52841) (xy 176.979326 -209.52841)
				(xy 176.848008 -209.52841) (xy 176.8221 -209.52841) (xy 176.8221 -209.75701) (xy 176.848008 -209.75701)
			)
		)
	)
	(zone
		(layer "F.Cu")
		(hatch none 0.5)
		(connect_pads
			(clearance 0)
		)
		(min_thickness 0.25)
		(keepout
			(tracks allowed)
			(vias allowed)
			(pads allowed)
			(copperpour allowed)
			(footprints allowed)
		)
		(placement
			(enabled no)
			(sheetname "")
		)
		(fill
			(thermal_gap 0.5)
			(thermal_bridge_width 0.5)
			(island_removal_mode 0)
		)
		(polygon
			(pts
				(xy 277.58771 -244.716554) (xy 277.58771 -244.272816) (xy 279.912826 -244.272816) (xy 279.912826 -244.716554)
			)
		)
	)
	(zone
		(layer "F.Cu")
		(hatch none 0.5)
		(connect_pads
			(clearance 0)
		)
		(min_thickness 0.25)
		(keepout
			(tracks allowed)
			(vias allowed)
			(pads allowed)
			(copperpour allowed)
			(footprints allowed)
		)
		(placement
			(enabled no)
			(sheetname "")
		)
		(fill
			(thermal_gap 0.5)
			(thermal_bridge_width 0.5)
			(island_removal_mode 0)
		)
		(polygon
			(pts
				(xy 165.335458 -310.90489) (xy 165.335458 -310.67629) (xy 167.367458 -310.67629) (xy 167.367458 -310.90489)
			)
		)
	)
	(zone
		(layer "F.Cu")
		(hatch none 0.5)
		(connect_pads
			(clearance 0)
		)
		(min_thickness 0.25)
		(keepout
			(tracks allowed)
			(vias allowed)
			(pads allowed)
			(copperpour allowed)
			(footprints allowed)
		)
		(placement
			(enabled no)
			(sheetname "")
		)
		(fill
			(thermal_gap 0.5)
			(thermal_bridge_width 0.5)
			(island_removal_mode 0)
		)
		(polygon
			(pts
				(xy 161.891726 -263.305036) (xy 161.891726 -263.076436) (xy 163.923726 -263.076436) (xy 163.923726 -263.305036)
			)
		)
	)
	(zone
		(layer "F.Cu")
		(hatch none 0.5)
		(connect_pads
			(clearance 0)
		)
		(min_thickness 0.25)
		(keepout
			(tracks allowed)
			(vias allowed)
			(pads allowed)
			(copperpour allowed)
			(footprints allowed)
		)
		(placement
			(enabled no)
			(sheetname "")
		)
		(fill
			(thermal_gap 0.5)
			(thermal_bridge_width 0.5)
			(island_removal_mode 0)
		)
		(polygon
			(pts
				(xy 425.75226 -5.888228) (xy 425.75226 -3.952748) (xy 427.92396 -3.952748) (xy 427.92396 -5.888228)
			)
		)
	)
	(zone
		(layer "F.Cu")
		(hatch none 0.5)
		(connect_pads
			(clearance 0)
		)
		(min_thickness 0.25)
		(keepout
			(tracks allowed)
			(vias allowed)
			(pads allowed)
			(copperpour allowed)
			(footprints not_allowed)
		)
		(placement
			(enabled no)
			(sheetname "")
		)
		(fill
			(thermal_gap 0.5)
			(thermal_bridge_width 0.5)
			(island_removal_mode 0)
		)
		(polygon
			(pts
				(arc
					(start 4.764278 -166.236904)
					(mid 3.756998 -165.045823)
					(end 2.999994 -163.681918)
				)
				(xy 2.999994 -166.236904)
			)
		)
	)
	(zone
		(layer "F.Cu")
		(hatch none 0.5)
		(connect_pads
			(clearance 0)
		)
		(min_thickness 0.25)
		(keepout
			(tracks not_allowed)
			(vias allowed)
			(pads allowed)
			(copperpour not_allowed)
			(footprints allowed)
		)
		(placement
			(enabled no)
			(sheetname "")
		)
		(fill
			(thermal_gap 0.5)
			(thermal_bridge_width 0.5)
			(island_removal_mode 0)
		)
		(polygon
			(pts
				(xy 417.716462 -181.259988) (xy 416.66414 -181.259988) (xy 416.603942 -181.320186) (xy 416.603942 -181.502304)
				(xy 417.716462 -181.502304)
			)
		)
	)
	(zone
		(layer "F.Cu")
		(hatch none 0.5)
		(connect_pads
			(clearance 0)
		)
		(min_thickness 0.25)
		(keepout
			(tracks allowed)
			(vias allowed)
			(pads allowed)
			(copperpour allowed)
			(footprints allowed)
		)
		(placement
			(enabled no)
			(sheetname "")
		)
		(fill
			(thermal_gap 0.5)
			(thermal_bridge_width 0.5)
			(island_removal_mode 0)
		)
		(polygon
			(pts
				(xy 138.75258 -220.116908) (xy 139.0396 -220.116908) (xy 139.07008 -220.086428) (xy 139.07008 -219.459048)
				(xy 138.98372 -219.372688) (xy 138.79576 -219.372688) (xy 138.7221 -219.446348) (xy 138.7221 -220.086428)
			)
		)
	)
	(zone
		(layer "F.Cu")
		(hatch none 0.5)
		(connect_pads
			(clearance 0)
		)
		(min_thickness 0.25)
		(keepout
			(tracks allowed)
			(vias allowed)
			(pads allowed)
			(copperpour allowed)
			(footprints not_allowed)
		)
		(placement
			(enabled no)
			(sheetname "")
		)
		(fill
			(thermal_gap 0.5)
			(thermal_bridge_width 0.5)
			(island_removal_mode 0)
		)
		(polygon
			(pts
				(arc
					(start 173.838362 -440.989974)
					(mid 171.923749 -437.257871)
					(end 172.160692 -433.07)
				)
				(xy 167.339264 -433.07) (xy 167.339264 -410.69006) (xy 77.499972 -410.69006) (xy 77.499972 -417.889944)
				(xy 94.499938 -417.889944)
				(arc
					(start 94.499938 -430.308766)
					(mid 100.499726 -427.599942)
					(end 106.499914 -430.308004)
				)
				(xy 106.499914 -418.869876) (xy 117.54993 -418.869876) (xy 117.54993 -440.989974) (xy 121.299986 -440.989974)
				(xy 121.299986 -417.889944) (xy 161.59988 -417.889944) (xy 161.59988 -440.989974)
			)
		)
	)
	(zone
		(layer "F.Cu")
		(hatch none 0.5)
		(connect_pads
			(clearance 0)
		)
		(min_thickness 0.25)
		(keepout
			(tracks allowed)
			(vias allowed)
			(pads allowed)
			(copperpour allowed)
			(footprints not_allowed)
		)
		(placement
			(enabled no)
			(sheetname "")
		)
		(fill
			(thermal_gap 0.5)
			(thermal_bridge_width 0.5)
			(island_removal_mode 0)
		)
		(polygon
			(pts
				(xy 112.15497 -73.000108) (xy 134.22503 -73.000108) (xy 134.22503 -68.49999) (xy 112.15497 -68.49999)
			)
		)
	)
	(zone
		(layer "F.Cu")
		(hatch none 0.5)
		(connect_pads
			(clearance 0)
		)
		(min_thickness 0.25)
		(keepout
			(tracks allowed)
			(vias allowed)
			(pads allowed)
			(copperpour allowed)
			(footprints allowed)
		)
		(placement
			(enabled no)
			(sheetname "")
		)
		(fill
			(thermal_gap 0.5)
			(thermal_bridge_width 0.5)
			(island_removal_mode 0)
		)
		(polygon
			(pts
				(xy 207.154526 -247.776238) (xy 209.186526 -247.776238) (xy 209.186526 -248.004838) (xy 207.154526 -248.004838)
				(xy 206.987902 -248.004838) (xy 206.987902 -247.776238)
			)
		)
	)
	(zone
		(layer "F.Cu")
		(hatch none 0.5)
		(connect_pads
			(clearance 0)
		)
		(min_thickness 0.25)
		(keepout
			(tracks allowed)
			(vias allowed)
			(pads allowed)
			(copperpour allowed)
			(footprints allowed)
		)
		(placement
			(enabled no)
			(sheetname "")
		)
		(fill
			(thermal_gap 0.5)
			(thermal_bridge_width 0.5)
			(island_removal_mode 0)
		)
		(polygon
			(pts
				(xy 307.76291 -205.616556) (xy 307.76291 -205.172818) (xy 310.088026 -205.172818) (xy 310.088026 -205.616556)
			)
		)
	)
	(zone
		(layer "F.Cu")
		(hatch none 0.5)
		(connect_pads
			(clearance 0)
		)
		(min_thickness 0.25)
		(keepout
			(tracks allowed)
			(vias allowed)
			(pads allowed)
			(copperpour allowed)
			(footprints allowed)
		)
		(placement
			(enabled no)
			(sheetname "")
		)
		(fill
			(thermal_gap 0.5)
			(thermal_bridge_width 0.5)
			(island_removal_mode 0)
		)
		(polygon
			(pts
				(xy 424.919394 -298.77639) (xy 426.951394 -298.77639) (xy 426.951394 -299.00499) (xy 424.919394 -299.00499)
				(xy 424.78325 -299.00499) (xy 424.73626 -299.00499) (xy 424.73626 -298.77639) (xy 424.78325 -298.77639)
			)
		)
	)
	(zone
		(layer "F.Cu")
		(hatch none 0.5)
		(connect_pads
			(clearance 0)
		)
		(min_thickness 0.25)
		(keepout
			(tracks allowed)
			(vias allowed)
			(pads allowed)
			(copperpour allowed)
			(footprints allowed)
		)
		(placement
			(enabled no)
			(sheetname "")
		)
		(fill
			(thermal_gap 0.5)
			(thermal_bridge_width 0.5)
			(island_removal_mode 0)
		)
		(polygon
			(pts
				(xy 161.891726 -294.754808) (xy 161.891726 -294.526208) (xy 163.923726 -294.526208) (xy 163.923726 -294.754808)
			)
		)
	)
	(zone
		(layer "F.Cu")
		(hatch none 0.5)
		(connect_pads
			(clearance 0)
		)
		(min_thickness 0.25)
		(keepout
			(tracks allowed)
			(vias allowed)
			(pads allowed)
			(copperpour allowed)
			(footprints allowed)
		)
		(placement
			(enabled no)
			(sheetname "")
		)
		(fill
			(thermal_gap 0.5)
			(thermal_bridge_width 0.5)
			(island_removal_mode 0)
		)
		(polygon
			(pts
				(xy 277.58771 -234.072684) (xy 279.912826 -234.072684) (xy 279.98547 -234.072684) (xy 279.98547 -234.995212)
				(xy 277.448518 -234.995212) (xy 277.448518 -234.072684)
			)
		)
	)
	(zone
		(layer "F.Cu")
		(hatch none 0.5)
		(connect_pads
			(clearance 0)
		)
		(min_thickness 0.25)
		(keepout
			(tracks allowed)
			(vias allowed)
			(pads allowed)
			(copperpour allowed)
			(footprints allowed)
		)
		(placement
			(enabled no)
			(sheetname "")
		)
		(fill
			(thermal_gap 0.5)
			(thermal_bridge_width 0.5)
			(island_removal_mode 0)
		)
		(polygon
			(pts
				(xy 413.275526 -197.854824) (xy 413.275526 -197.626224) (xy 415.307526 -197.626224) (xy 415.307526 -197.854824)
			)
		)
	)
	(zone
		(layer "F.Cu")
		(hatch none 0.5)
		(connect_pads
			(clearance 0)
		)
		(min_thickness 0.25)
		(keepout
			(tracks allowed)
			(vias allowed)
			(pads allowed)
			(copperpour allowed)
			(footprints allowed)
		)
		(placement
			(enabled no)
			(sheetname "")
		)
		(fill
			(thermal_gap 0.5)
			(thermal_bridge_width 0.5)
			(island_removal_mode 0)
		)
		(polygon
			(pts
				(xy 274.143978 -239.17275) (xy 276.469094 -239.17275) (xy 276.530562 -239.17275) (xy 276.530562 -240.096802)
				(xy 274.01393 -240.096802) (xy 274.01393 -239.17275)
			)
		)
	)
	(zone
		(layer "F.Cu")
		(hatch none 0.5)
		(connect_pads
			(clearance 0)
		)
		(min_thickness 0.25)
		(keepout
			(tracks allowed)
			(vias allowed)
			(pads allowed)
			(copperpour allowed)
			(footprints allowed)
		)
		(placement
			(enabled no)
			(sheetname "")
		)
		(fill
			(thermal_gap 0.5)
			(thermal_bridge_width 0.5)
			(island_removal_mode 0)
		)
		(polygon
			(pts
				(xy 443.450726 -205.504796) (xy 443.450726 -205.276196) (xy 445.482726 -205.276196) (xy 445.482726 -205.504796)
			)
		)
	)
	(zone
		(layer "F.Cu")
		(hatch none 0.5)
		(connect_pads
			(clearance 0)
		)
		(min_thickness 0.25)
		(keepout
			(tracks allowed)
			(vias allowed)
			(pads allowed)
			(copperpour allowed)
			(footprints allowed)
		)
		(placement
			(enabled no)
			(sheetname "")
		)
		(fill
			(thermal_gap 0.5)
			(thermal_bridge_width 0.5)
			(island_removal_mode 0)
		)
		(polygon
			(pts
				(xy 207.154526 -201.026268) (xy 209.186526 -201.026268) (xy 209.186526 -201.254868) (xy 207.154526 -201.254868)
				(xy 207.023208 -201.254868) (xy 206.9973 -201.254868) (xy 206.9973 -201.026268) (xy 207.023208 -201.026268)
			)
		)
	)
	(zone
		(layer "F.Cu")
		(hatch none 0.5)
		(connect_pads
			(clearance 0)
		)
		(min_thickness 0.25)
		(keepout
			(tracks allowed)
			(vias allowed)
			(pads allowed)
			(copperpour allowed)
			(footprints allowed)
		)
		(placement
			(enabled no)
			(sheetname "")
		)
		(fill
			(thermal_gap 0.5)
			(thermal_bridge_width 0.5)
			(island_removal_mode 0)
		)
		(polygon
			(pts
				(xy 195.510658 -300.705012) (xy 195.510658 -300.476412) (xy 197.542658 -300.476412) (xy 197.542658 -300.705012)
			)
		)
	)
	(zone
		(layer "F.Cu")
		(hatch none 0.5)
		(connect_pads
			(clearance 0)
		)
		(min_thickness 0.25)
		(keepout
			(tracks allowed)
			(vias allowed)
			(pads allowed)
			(copperpour allowed)
			(footprints allowed)
		)
		(placement
			(enabled no)
			(sheetname "")
		)
		(fill
			(thermal_gap 0.5)
			(thermal_bridge_width 0.5)
			(island_removal_mode 0)
		)
		(polygon
			(pts
				(xy 443.450726 -316.004956) (xy 443.450726 -315.776356) (xy 445.482726 -315.776356) (xy 445.482726 -316.004956)
			)
		)
	)
	(zone
		(layer "F.Cu")
		(hatch none 0.5)
		(connect_pads
			(clearance 0)
		)
		(min_thickness 0.25)
		(keepout
			(tracks allowed)
			(vias allowed)
			(pads allowed)
			(copperpour allowed)
			(footprints allowed)
		)
		(placement
			(enabled no)
			(sheetname "")
		)
		(fill
			(thermal_gap 0.5)
			(thermal_bridge_width 0.5)
			(island_removal_mode 0)
		)
		(polygon
			(pts
				(xy 335.55686 -289.024568) (xy 335.84388 -289.024568) (xy 335.87436 -288.994088) (xy 335.87436 -288.366708)
				(xy 335.788 -288.280348) (xy 335.60004 -288.280348) (xy 335.52638 -288.354008) (xy 335.52638 -288.994088)
			)
		)
	)
	(zone
		(layer "F.Cu")
		(hatch none 0.5)
		(connect_pads
			(clearance 0)
		)
		(min_thickness 0.25)
		(keepout
			(tracks allowed)
			(vias allowed)
			(pads allowed)
			(copperpour allowed)
			(footprints allowed)
		)
		(placement
			(enabled no)
			(sheetname "")
		)
		(fill
			(thermal_gap 0.5)
			(thermal_bridge_width 0.5)
			(island_removal_mode 0)
		)
		(polygon
			(pts
				(xy 207.154526 -303.876202) (xy 209.186526 -303.876202) (xy 209.186526 -304.104802) (xy 207.154526 -304.104802)
				(xy 207.023208 -304.104802) (xy 206.9973 -304.104802) (xy 206.9973 -303.876202) (xy 207.023208 -303.876202)
			)
		)
	)
	(zone
		(layer "F.Cu")
		(hatch none 0.5)
		(connect_pads
			(clearance 0)
		)
		(min_thickness 0.25)
		(keepout
			(tracks allowed)
			(vias allowed)
			(pads allowed)
			(copperpour allowed)
			(footprints allowed)
		)
		(placement
			(enabled no)
			(sheetname "")
		)
		(fill
			(thermal_gap 0.5)
			(thermal_bridge_width 0.5)
			(island_removal_mode 0)
		)
		(polygon
			(pts
				(xy 210.598258 -286.254952) (xy 210.598258 -286.026352) (xy 212.630258 -286.026352) (xy 212.630258 -286.254952)
			)
		)
	)
	(zone
		(layer "F.Cu")
		(hatch none 0.5)
		(connect_pads
			(clearance 0)
		)
		(min_thickness 0.25)
		(keepout
			(tracks allowed)
			(vias allowed)
			(pads allowed)
			(copperpour allowed)
			(footprints allowed)
		)
		(placement
			(enabled no)
			(sheetname "")
		)
		(fill
			(thermal_gap 0.5)
			(thermal_bridge_width 0.5)
			(island_removal_mode 0)
		)
		(polygon
			(pts
				(xy 458.538326 -220.804994) (xy 458.538326 -220.576394) (xy 460.570326 -220.576394) (xy 460.570326 -220.804994)
			)
		)
	)
	(zone
		(layer "F.Cu")
		(hatch none 0.5)
		(connect_pads
			(clearance 0)
		)
		(min_thickness 0.25)
		(keepout
			(tracks not_allowed)
			(vias allowed)
			(pads allowed)
			(copperpour not_allowed)
			(footprints allowed)
		)
		(placement
			(enabled no)
			(sheetname "")
		)
		(fill
			(thermal_gap 0.5)
			(thermal_bridge_width 0.5)
			(island_removal_mode 0)
		)
		(polygon
			(pts
				(arc
					(start 446.300098 -435.600094)
					(mid 448.80022 -433.099972)
					(end 451.300088 -435.600094)
				)
				(arc
					(start 451.300088 -435.600094)
					(mid 448.80022 -438.099962)
					(end 446.300098 -435.600094)
				)
			)
		)
	)
	(zone
		(layer "F.Cu")
		(hatch none 0.5)
		(connect_pads
			(clearance 0)
		)
		(min_thickness 0.25)
		(keepout
			(tracks allowed)
			(vias allowed)
			(pads allowed)
			(copperpour allowed)
			(footprints allowed)
		)
		(placement
			(enabled no)
			(sheetname "")
		)
		(fill
			(thermal_gap 0.5)
			(thermal_bridge_width 0.5)
			(island_removal_mode 0)
		)
		(polygon
			(pts
				(xy 44.735242 -260.866636) (xy 44.735242 -260.422898) (xy 47.060358 -260.422898) (xy 47.060358 -260.866636)
			)
		)
	)
	(zone
		(layer "F.Cu")
		(hatch none 0.5)
		(connect_pads
			(clearance 0)
		)
		(min_thickness 0.25)
		(keepout
			(tracks allowed)
			(vias allowed)
			(pads allowed)
			(copperpour allowed)
			(footprints allowed)
		)
		(placement
			(enabled no)
			(sheetname "")
		)
		(fill
			(thermal_gap 0.5)
			(thermal_bridge_width 0.5)
			(island_removal_mode 0)
		)
		(polygon
			(pts
				(xy 311.743598 -277.512526) (xy 311.613296 -277.382224) (xy 311.613296 -277.080218) (xy 311.754266 -276.939248)
				(xy 314.230766 -276.939248) (xy 314.343542 -277.052024) (xy 314.343542 -277.44293) (xy 314.271406 -277.515066)
				(xy 314.199778 -277.515066) (xy 314.199778 -277.866602) (xy 314.15228 -277.866602) (xy 311.91708 -277.866602)
				(xy 311.743598 -277.866602)
			)
		)
	)
	(zone
		(layer "F.Cu")
		(hatch none 0.5)
		(connect_pads
			(clearance 0)
		)
		(min_thickness 0.25)
		(keepout
			(tracks allowed)
			(vias allowed)
			(pads allowed)
			(copperpour allowed)
			(footprints allowed)
		)
		(placement
			(enabled no)
			(sheetname "")
		)
		(fill
			(thermal_gap 0.5)
			(thermal_bridge_width 0.5)
			(island_removal_mode 0)
		)
		(polygon
			(pts
				(xy 210.598258 -273.504914) (xy 210.598258 -273.276314) (xy 212.630258 -273.276314) (xy 212.630258 -273.504914)
			)
		)
	)
	(zone
		(layer "F.Cu")
		(hatch none 0.5)
		(connect_pads
			(clearance 0)
		)
		(min_thickness 0.25)
		(keepout
			(tracks allowed)
			(vias allowed)
			(pads allowed)
			(copperpour allowed)
			(footprints allowed)
		)
		(placement
			(enabled no)
			(sheetname "")
		)
		(fill
			(thermal_gap 0.5)
			(thermal_bridge_width 0.5)
			(island_removal_mode 0)
		)
		(polygon
			(pts
				(xy 360.748834 -213.244938) (xy 383.755138 -213.244938) (xy 383.829052 -213.244938) (xy 383.962148 -213.111842)
				(xy 383.962148 -213.037928) (xy 383.962148 -208.046828) (xy 381.126238 -205.210918) (xy 354.098352 -205.210918)
				(xy 351.21596 -205.210918) (xy 351.060766 -205.366112) (xy 351.060766 -206.178912) (xy 358.126792 -213.244938)
			)
		)
	)
	(zone
		(layer "F.Cu")
		(hatch none 0.5)
		(connect_pads
			(clearance 0)
		)
		(min_thickness 0.25)
		(keepout
			(tracks allowed)
			(vias allowed)
			(pads allowed)
			(copperpour allowed)
			(footprints allowed)
		)
		(placement
			(enabled no)
			(sheetname "")
		)
		(fill
			(thermal_gap 0.5)
			(thermal_bridge_width 0.5)
			(island_removal_mode 0)
		)
		(polygon
			(pts
				(xy 405.731726 -277.526496) (xy 407.763726 -277.526496) (xy 407.763726 -277.528782) (xy 407.942542 -277.528782)
				(xy 407.942542 -277.766018) (xy 408.080464 -277.766018) (xy 408.123644 -277.809198) (xy 408.123644 -277.94204)
				(xy 408.123644 -278.246078) (xy 408.051 -278.318722) (xy 405.510746 -278.318722) (xy 405.369522 -278.177498)
				(xy 405.369522 -277.980394) (xy 405.451056 -277.89886) (xy 405.451056 -277.526496) (xy 405.548592 -277.526496)
				(xy 405.595582 -277.526496)
			)
		)
	)
	(zone
		(layer "F.Cu")
		(hatch none 0.5)
		(connect_pads
			(clearance 0)
		)
		(min_thickness 0.25)
		(keepout
			(tracks allowed)
			(vias allowed)
			(pads allowed)
			(copperpour allowed)
			(footprints allowed)
		)
		(placement
			(enabled no)
			(sheetname "")
		)
		(fill
			(thermal_gap 0.5)
			(thermal_bridge_width 0.5)
			(island_removal_mode 0)
		)
		(polygon
			(pts
				(xy 14.560042 -299.966634) (xy 14.560042 -299.522896) (xy 16.885158 -299.522896) (xy 16.885158 -299.966634)
			)
		)
	)
	(zone
		(layer "F.Cu")
		(hatch none 0.5)
		(connect_pads
			(clearance 0)
		)
		(min_thickness 0.25)
		(keepout
			(tracks allowed)
			(vias allowed)
			(pads allowed)
			(copperpour allowed)
			(footprints allowed)
		)
		(placement
			(enabled no)
			(sheetname "")
		)
		(fill
			(thermal_gap 0.5)
			(thermal_bridge_width 0.5)
			(island_removal_mode 0)
		)
		(polygon
			(pts
				(xy 262.50011 -292.316662) (xy 262.50011 -291.872924) (xy 264.825226 -291.872924) (xy 264.825226 -292.316662)
			)
		)
	)
	(zone
		(net "GND")
		(layer "F.Cu")
		(hatch none 0.5)
		(connect_pads
			(clearance 0.5)
		)
		(min_thickness 0.25)
		(fill yes
			(thermal_gap 0.5)
			(thermal_bridge_width 0.5)
			(island_removal_mode 0)
		)
		(polygon
			(pts
				(xy 191.625982 -18.642584) (xy 191.625982 -20.850352) (xy 194.699382 -23.923752) (xy 194.699382 -29.460952)
				(xy 193.301366 -30.858968) (xy 191.07912 -30.858968) (xy 190.686182 -31.251906) (xy 190.686182 -33.474152)
				(xy 190.9318 -33.71977) (xy 190.9318 -33.736788) (xy 195.56476 -33.736788) (xy 195.969382 -33.332166)
				(xy 195.969382 -18.59788) (xy 195.917566 -18.546064) (xy 191.722502 -18.546064)
			)
		)
	)
	(zone
		(layer "F.Cu")
		(hatch none 0.5)
		(connect_pads
			(clearance 0)
		)
		(min_thickness 0.25)
		(keepout
			(tracks allowed)
			(vias allowed)
			(pads allowed)
			(copperpour allowed)
			(footprints allowed)
		)
		(placement
			(enabled no)
			(sheetname "")
		)
		(fill
			(thermal_gap 0.5)
			(thermal_bridge_width 0.5)
			(island_removal_mode 0)
		)
		(polygon
			(pts
				(xy 29.647642 -212.416644) (xy 29.647642 -211.972906) (xy 31.972758 -211.972906) (xy 31.972758 -212.416644)
			)
		)
	)
	(zone
		(layer "F.Cu")
		(hatch none 0.5)
		(connect_pads
			(clearance 0)
		)
		(min_thickness 0.25)
		(keepout
			(tracks allowed)
			(vias allowed)
			(pads allowed)
			(copperpour allowed)
			(footprints allowed)
		)
		(placement
			(enabled no)
			(sheetname "")
		)
		(fill
			(thermal_gap 0.5)
			(thermal_bridge_width 0.5)
			(island_removal_mode 0)
		)
		(polygon
			(pts
				(xy 292.67531 -299.966634) (xy 292.67531 -299.522896) (xy 295.000426 -299.522896) (xy 295.000426 -299.966634)
			)
		)
	)
	(zone
		(layer "F.Cu")
		(hatch none 0.5)
		(connect_pads
			(clearance 0)
		)
		(min_thickness 0.25)
		(keepout
			(tracks allowed)
			(vias allowed)
			(pads allowed)
			(copperpour allowed)
			(footprints allowed)
		)
		(placement
			(enabled no)
			(sheetname "")
		)
		(fill
			(thermal_gap 0.5)
			(thermal_bridge_width 0.5)
			(island_removal_mode 0)
		)
		(polygon
			(pts
				(xy 85.71738 -284.168088) (xy 86.0044 -284.168088) (xy 86.03488 -284.137608) (xy 86.03488 -283.510228)
				(xy 85.94852 -283.423868) (xy 85.76056 -283.423868) (xy 85.6869 -283.497528) (xy 85.6869 -284.137608)
			)
		)
	)
	(zone
		(layer "F.Cu")
		(hatch none 0.5)
		(connect_pads
			(clearance 0)
		)
		(min_thickness 0.25)
		(keepout
			(tracks allowed)
			(vias allowed)
			(pads allowed)
			(copperpour allowed)
			(footprints allowed)
		)
		(placement
			(enabled no)
			(sheetname "")
		)
		(fill
			(thermal_gap 0.5)
			(thermal_bridge_width 0.5)
			(island_removal_mode 0)
		)
		(polygon
			(pts
				(xy 440.006994 -308.126384) (xy 442.038994 -308.126384) (xy 442.038994 -308.354984) (xy 440.006994 -308.354984)
				(xy 439.87085 -308.354984) (xy 439.82386 -308.354984) (xy 439.82386 -308.126384) (xy 439.87085 -308.126384)
			)
		)
	)
	(zone
		(layer "F.Cu")
		(hatch none 0.5)
		(connect_pads
			(clearance 0)
		)
		(min_thickness 0.25)
		(keepout
			(tracks allowed)
			(vias allowed)
			(pads allowed)
			(copperpour allowed)
			(footprints allowed)
		)
		(placement
			(enabled no)
			(sheetname "")
		)
		(fill
			(thermal_gap 0.5)
			(thermal_bridge_width 0.5)
			(island_removal_mode 0)
		)
		(polygon
			(pts
				(xy 63.977012 -216.666572) (xy 63.977012 -216.222834) (xy 66.186812 -216.222834) (xy 66.186812 -216.666572)
			)
		)
	)
	(zone
		(layer "F.Cu")
		(hatch none 0.5)
		(connect_pads
			(clearance 0)
		)
		(min_thickness 0.25)
		(keepout
			(tracks allowed)
			(vias allowed)
			(pads allowed)
			(copperpour allowed)
			(footprints allowed)
		)
		(placement
			(enabled no)
			(sheetname "")
		)
		(fill
			(thermal_gap 0.5)
			(thermal_bridge_width 0.5)
			(island_removal_mode 0)
		)
		(polygon
			(pts
				(xy 210.598258 -293.05504) (xy 210.598258 -292.82644) (xy 212.630258 -292.82644) (xy 212.630258 -293.05504)
			)
		)
	)
	(zone
		(layer "F.Cu")
		(hatch none 0.5)
		(connect_pads
			(clearance 0)
		)
		(min_thickness 0.25)
		(keepout
			(tracks allowed)
			(vias allowed)
			(pads allowed)
			(copperpour allowed)
			(footprints allowed)
		)
		(placement
			(enabled no)
			(sheetname "")
		)
		(fill
			(thermal_gap 0.5)
			(thermal_bridge_width 0.5)
			(island_removal_mode 0)
		)
		(polygon
			(pts
				(xy 455.094594 -222.276416) (xy 457.126594 -222.276416) (xy 457.126594 -222.505016) (xy 455.094594 -222.505016)
				(xy 454.95845 -222.505016) (xy 454.91146 -222.505016) (xy 454.91146 -222.276416) (xy 454.95845 -222.276416)
			)
		)
	)
	(zone
		(layer "F.Cu")
		(hatch none 0.5)
		(connect_pads
			(clearance 0)
		)
		(min_thickness 0.25)
		(keepout
			(tracks allowed)
			(vias allowed)
			(pads allowed)
			(copperpour allowed)
			(footprints allowed)
		)
		(placement
			(enabled no)
			(sheetname "")
		)
		(fill
			(thermal_gap 0.5)
			(thermal_bridge_width 0.5)
			(island_removal_mode 0)
		)
		(polygon
			(pts
				(xy 413.275526 -248.854976) (xy 413.275526 -248.626376) (xy 415.307526 -248.626376) (xy 415.307526 -248.854976)
			)
		)
	)
	(zone
		(layer "F.Cu")
		(hatch none 0.5)
		(connect_pads
			(clearance 0)
		)
		(min_thickness 0.25)
		(keepout
			(tracks allowed)
			(vias allowed)
			(pads allowed)
			(copperpour allowed)
			(footprints allowed)
		)
		(placement
			(enabled no)
			(sheetname "")
		)
		(fill
			(thermal_gap 0.5)
			(thermal_bridge_width 0.5)
			(island_removal_mode 0)
		)
		(polygon
			(pts
				(xy 165.335458 -211.455) (xy 165.335458 -211.2264) (xy 167.367458 -211.2264) (xy 167.367458 -211.455)
			)
		)
	)
	(zone
		(layer "F.Cu")
		(hatch none 0.5)
		(connect_pads
			(clearance 0)
		)
		(min_thickness 0.25)
		(keepout
			(tracks allowed)
			(vias allowed)
			(pads allowed)
			(copperpour allowed)
			(footprints allowed)
		)
		(placement
			(enabled no)
			(sheetname "")
		)
		(fill
			(thermal_gap 0.5)
			(thermal_bridge_width 0.5)
			(island_removal_mode 0)
		)
		(polygon
			(pts
				(xy 157.791658 -308.354984) (xy 157.791658 -308.126384) (xy 159.823658 -308.126384) (xy 159.823658 -308.354984)
			)
		)
	)
	(zone
		(layer "F.Cu")
		(hatch none 0.5)
		(connect_pads
			(clearance 0)
		)
		(min_thickness 0.25)
		(keepout
			(tracks allowed)
			(vias allowed)
			(pads allowed)
			(copperpour allowed)
			(footprints allowed)
		)
		(placement
			(enabled no)
			(sheetname "")
		)
		(fill
			(thermal_gap 0.5)
			(thermal_bridge_width 0.5)
			(island_removal_mode 0)
		)
		(polygon
			(pts
				(xy 413.851344 -404.802594) (xy 413.851344 -399.959576) (xy 415.73577 -399.959576) (xy 415.73577 -404.802594)
			)
		)
	)
	(zone
		(layer "F.Cu")
		(hatch none 0.5)
		(connect_pads
			(clearance 0)
		)
		(min_thickness 0.25)
		(keepout
			(tracks allowed)
			(vias allowed)
			(pads allowed)
			(copperpour allowed)
			(footprints allowed)
		)
		(placement
			(enabled no)
			(sheetname "")
		)
		(fill
			(thermal_gap 0.5)
			(thermal_bridge_width 0.5)
			(island_removal_mode 0)
		)
		(polygon
			(pts
				(xy 262.50011 -311.866534) (xy 262.50011 -311.422796) (xy 264.825226 -311.422796) (xy 264.825226 -311.866534)
			)
		)
	)
	(zone
		(layer "F.Cu")
		(hatch none 0.5)
		(connect_pads
			(clearance 0)
		)
		(min_thickness 0.25)
		(keepout
			(tracks allowed)
			(vias allowed)
			(pads allowed)
			(copperpour allowed)
			(footprints allowed)
		)
		(placement
			(enabled no)
			(sheetname "")
		)
		(fill
			(thermal_gap 0.5)
			(thermal_bridge_width 0.5)
			(island_removal_mode 0)
		)
		(polygon
			(pts
				(xy 417.778184 -18.55978) (xy 417.778184 -15.425166) (xy 419.556946 -15.425166) (xy 419.556946 -18.55978)
			)
		)
	)
	(zone
		(layer "F.Cu")
		(hatch none 0.5)
		(connect_pads
			(clearance 0)
		)
		(min_thickness 0.25)
		(keepout
			(tracks allowed)
			(vias allowed)
			(pads allowed)
			(copperpour allowed)
			(footprints allowed)
		)
		(placement
			(enabled no)
			(sheetname "")
		)
		(fill
			(thermal_gap 0.5)
			(thermal_bridge_width 0.5)
			(island_removal_mode 0)
		)
		(polygon
			(pts
				(xy 180.423058 -269.254986) (xy 180.423058 -269.026386) (xy 182.455058 -269.026386) (xy 182.455058 -269.254986)
			)
		)
	)
	(zone
		(layer "F.Cu")
		(hatch none 0.5)
		(connect_pads
			(clearance 0)
		)
		(min_thickness 0.25)
		(keepout
			(tracks allowed)
			(vias allowed)
			(pads allowed)
			(copperpour allowed)
			(footprints allowed)
		)
		(placement
			(enabled no)
			(sheetname "")
		)
		(fill
			(thermal_gap 0.5)
			(thermal_bridge_width 0.5)
			(island_removal_mode 0)
		)
		(polygon
			(pts
				(xy 332.133956 -232.546652) (xy 332.336902 -232.749598) (xy 332.379828 -232.749598) (xy 332.823566 -232.306114)
				(xy 332.823566 -232.18394) (xy 332.690724 -232.050844) (xy 332.586584 -232.050844) (xy 332.133956 -232.503472)
			)
		)
	)
	(zone
		(layer "F.Cu")
		(hatch none 0.5)
		(connect_pads
			(clearance 0)
		)
		(min_thickness 0.25)
		(keepout
			(tracks allowed)
			(vias allowed)
			(pads allowed)
			(copperpour allowed)
			(footprints allowed)
		)
		(placement
			(enabled no)
			(sheetname "")
		)
		(fill
			(thermal_gap 0.5)
			(thermal_bridge_width 0.5)
			(island_removal_mode 0)
		)
		(polygon
			(pts
				(xy 59.822842 -311.866534) (xy 59.822842 -311.422796) (xy 62.147958 -311.422796) (xy 62.147958 -311.866534)
			)
		)
	)
	(zone
		(layer "F.Cu")
		(hatch none 0.5)
		(connect_pads
			(clearance 0)
		)
		(min_thickness 0.25)
		(keepout
			(tracks allowed)
			(vias allowed)
			(pads allowed)
			(copperpour allowed)
			(footprints allowed)
		)
		(placement
			(enabled no)
			(sheetname "")
		)
		(fill
			(thermal_gap 0.5)
			(thermal_bridge_width 0.5)
			(island_removal_mode 0)
		)
		(polygon
			(pts
				(xy 195.510658 -203.805028) (xy 195.510658 -203.576428) (xy 197.542658 -203.576428) (xy 197.542658 -203.805028)
			)
		)
	)
	(zone
		(layer "F.Cu")
		(hatch none 0.5)
		(connect_pads
			(clearance 0)
		)
		(min_thickness 0.25)
		(keepout
			(tracks allowed)
			(vias allowed)
			(pads allowed)
			(copperpour allowed)
			(footprints allowed)
		)
		(placement
			(enabled no)
			(sheetname "")
		)
		(fill
			(thermal_gap 0.5)
			(thermal_bridge_width 0.5)
			(island_removal_mode 0)
		)
		(polygon
			(pts
				(xy 210.598258 -272.65503) (xy 210.598258 -272.42643) (xy 212.630258 -272.42643) (xy 212.630258 -272.65503)
			)
		)
	)
	(zone
		(layer "F.Cu")
		(hatch none 0.5)
		(connect_pads
			(clearance 0)
		)
		(min_thickness 0.25)
		(keepout
			(tracks allowed)
			(vias allowed)
			(pads allowed)
			(copperpour allowed)
			(footprints not_allowed)
		)
		(placement
			(enabled no)
			(sheetname "")
		)
		(fill
			(thermal_gap 0.5)
			(thermal_bridge_width 0.5)
			(island_removal_mode 0)
		)
		(polygon
			(pts
				(xy 168.36263 -79.774288) (xy 55.559452 -79.762604) (xy 55.558944 -82.762598) (xy 168.362122 -82.774282)
			)
		)
	)
	(zone
		(layer "F.Cu")
		(hatch none 0.5)
		(connect_pads
			(clearance 0)
		)
		(min_thickness 0.25)
		(keepout
			(tracks allowed)
			(vias allowed)
			(pads allowed)
			(copperpour allowed)
			(footprints allowed)
		)
		(placement
			(enabled no)
			(sheetname "")
		)
		(fill
			(thermal_gap 0.5)
			(thermal_bridge_width 0.5)
			(island_removal_mode 0)
		)
		(polygon
			(pts
				(xy 458.538326 -304.95494) (xy 458.538326 -304.72634) (xy 460.570326 -304.72634) (xy 460.570326 -304.95494)
			)
		)
	)
	(zone
		(layer "F.Cu")
		(hatch none 0.5)
		(connect_pads
			(clearance 0)
		)
		(min_thickness 0.25)
		(keepout
			(tracks allowed)
			(vias allowed)
			(pads allowed)
			(copperpour allowed)
			(footprints allowed)
		)
		(placement
			(enabled no)
			(sheetname "")
		)
		(fill
			(thermal_gap 0.5)
			(thermal_bridge_width 0.5)
			(island_removal_mode 0)
		)
		(polygon
			(pts
				(xy 455.094594 -245.454932) (xy 455.094594 -245.226332) (xy 457.126594 -245.226332) (xy 457.126594 -245.454932)
			)
		)
	)
	(zone
		(layer "F.Cu")
		(hatch none 0.5)
		(connect_pads
			(clearance 0)
		)
		(min_thickness 0.25)
		(keepout
			(tracks allowed)
			(vias allowed)
			(pads allowed)
			(copperpour allowed)
			(footprints allowed)
		)
		(placement
			(enabled no)
			(sheetname "")
		)
		(fill
			(thermal_gap 0.5)
			(thermal_bridge_width 0.5)
			(island_removal_mode 0)
		)
		(polygon
			(pts
				(xy 29.647642 -198.816468) (xy 29.647642 -198.37273) (xy 31.972758 -198.37273) (xy 31.972758 -198.816468)
			)
		)
	)
	(zone
		(layer "F.Cu")
		(hatch none 0.5)
		(connect_pads
			(clearance 0)
		)
		(min_thickness 0.25)
		(keepout
			(tracks allowed)
			(vias allowed)
			(pads allowed)
			(copperpour allowed)
			(footprints allowed)
		)
		(placement
			(enabled no)
			(sheetname "")
		)
		(fill
			(thermal_gap 0.5)
			(thermal_bridge_width 0.5)
			(island_removal_mode 0)
		)
		(polygon
			(pts
				(xy 233.072686 -128.796034) (xy 233.072686 -124.759974) (xy 236.953806 -124.759974) (xy 236.953806 -128.796034)
			)
		)
	)
	(zone
		(layer "F.Cu")
		(hatch none 0.5)
		(connect_pads
			(clearance 0)
		)
		(min_thickness 0.25)
		(keepout
			(tracks allowed)
			(vias allowed)
			(pads allowed)
			(copperpour allowed)
			(footprints allowed)
		)
		(placement
			(enabled no)
			(sheetname "")
		)
		(fill
			(thermal_gap 0.5)
			(thermal_bridge_width 0.5)
			(island_removal_mode 0)
		)
		(polygon
			(pts
				(xy 180.08854 -45.463968) (xy 180.08854 -43.668188) (xy 182.92064 -43.668188) (xy 182.92064 -45.463968)
			)
		)
	)
	(zone
		(layer "F.Cu")
		(hatch none 0.5)
		(connect_pads
			(clearance 0)
		)
		(min_thickness 0.25)
		(keepout
			(tracks allowed)
			(vias allowed)
			(pads allowed)
			(copperpour allowed)
			(footprints allowed)
		)
		(placement
			(enabled no)
			(sheetname "")
		)
		(fill
			(thermal_gap 0.5)
			(thermal_bridge_width 0.5)
			(island_removal_mode 0)
		)
		(polygon
			(pts
				(xy 137.98804 -286.576008) (xy 138.27506 -286.576008) (xy 138.30554 -286.545528) (xy 138.30554 -285.918148)
				(xy 138.21918 -285.831788) (xy 138.03122 -285.831788) (xy 137.95756 -285.905448) (xy 137.95756 -286.545528)
			)
		)
	)
	(zone
		(layer "F.Cu")
		(hatch none 0.5)
		(connect_pads
			(clearance 0)
		)
		(min_thickness 0.25)
		(keepout
			(tracks allowed)
			(vias allowed)
			(pads allowed)
			(copperpour allowed)
			(footprints allowed)
		)
		(placement
			(enabled no)
			(sheetname "")
		)
		(fill
			(thermal_gap 0.5)
			(thermal_bridge_width 0.5)
			(island_removal_mode 0)
		)
		(polygon
			(pts
				(xy 104.273604 -332.908402) (xy 102.457504 -332.908402) (xy 102.457504 -331.529182) (xy 104.273604 -331.529182)
			)
		)
	)
	(zone
		(layer "F.Cu")
		(hatch none 0.5)
		(connect_pads
			(clearance 0)
		)
		(min_thickness 0.25)
		(keepout
			(tracks allowed)
			(vias allowed)
			(pads allowed)
			(copperpour allowed)
			(footprints allowed)
		)
		(placement
			(enabled no)
			(sheetname "")
		)
		(fill
			(thermal_gap 0.5)
			(thermal_bridge_width 0.5)
			(island_removal_mode 0)
		)
		(polygon
			(pts
				(xy 207.154526 -231.62641) (xy 209.186526 -231.62641) (xy 209.186526 -231.85501) (xy 207.154526 -231.85501)
				(xy 207.018382 -231.85501) (xy 206.971392 -231.85501) (xy 206.971392 -231.62641) (xy 207.018382 -231.62641)
			)
		)
	)
	(zone
		(layer "F.Cu")
		(hatch none 0.5)
		(connect_pads
			(clearance 0)
		)
		(min_thickness 0.25)
		(keepout
			(tracks allowed)
			(vias allowed)
			(pads allowed)
			(copperpour allowed)
			(footprints allowed)
		)
		(placement
			(enabled no)
			(sheetname "")
		)
		(fill
			(thermal_gap 0.5)
			(thermal_bridge_width 0.5)
			(island_removal_mode 0)
		)
		(polygon
			(pts
				(xy 29.87294 -162.771328) (xy 29.87294 -166.637208) (xy 30.10408 -166.868348) (xy 31.46298 -166.868348)
				(xy 32.00654 -166.324788) (xy 32.00654 -163.690808) (xy 32.53486 -163.162488) (xy 32.84982 -163.162488)
				(xy 32.84982 -162.166808) (xy 32.69996 -162.016948) (xy 30.62732 -162.016948)
			)
		)
	)
	(zone
		(layer "F.Cu")
		(hatch none 0.5)
		(connect_pads
			(clearance 0)
		)
		(min_thickness 0.25)
		(keepout
			(tracks allowed)
			(vias allowed)
			(pads allowed)
			(copperpour allowed)
			(footprints allowed)
		)
		(placement
			(enabled no)
			(sheetname "")
		)
		(fill
			(thermal_gap 0.5)
			(thermal_bridge_width 0.5)
			(island_removal_mode 0)
		)
		(polygon
			(pts
				(xy 386.863336 -258.243832) (xy 387.066282 -258.446778) (xy 387.109208 -258.446778) (xy 387.552946 -258.003294)
				(xy 387.552946 -257.88112) (xy 387.420104 -257.748024) (xy 387.315964 -257.748024) (xy 386.863336 -258.200652)
			)
		)
	)
	(zone
		(layer "F.Cu")
		(hatch none 0.5)
		(connect_pads
			(clearance 0)
		)
		(min_thickness 0.25)
		(keepout
			(tracks allowed)
			(vias allowed)
			(pads allowed)
			(copperpour allowed)
			(footprints allowed)
		)
		(placement
			(enabled no)
			(sheetname "")
		)
		(fill
			(thermal_gap 0.5)
			(thermal_bridge_width 0.5)
			(island_removal_mode 0)
		)
		(polygon
			(pts
				(xy 386.282184 -404.802594) (xy 386.282184 -399.959576) (xy 388.16661 -399.959576) (xy 388.16661 -404.802594)
			)
		)
	)
	(zone
		(layer "F.Cu")
		(hatch none 0.5)
		(connect_pads
			(clearance 0)
		)
		(min_thickness 0.25)
		(keepout
			(tracks allowed)
			(vias allowed)
			(pads allowed)
			(copperpour allowed)
			(footprints allowed)
		)
		(placement
			(enabled no)
			(sheetname "")
		)
		(fill
			(thermal_gap 0.5)
			(thermal_bridge_width 0.5)
			(island_removal_mode 0)
		)
		(polygon
			(pts
				(xy 44.735242 -215.816434) (xy 44.735242 -215.372696) (xy 47.060358 -215.372696) (xy 47.060358 -215.816434)
			)
		)
	)
	(zone
		(layer "F.Cu")
		(hatch none 0.5)
		(connect_pads
			(clearance 0)
		)
		(min_thickness 0.25)
		(keepout
			(tracks allowed)
			(vias allowed)
			(pads allowed)
			(copperpour allowed)
			(footprints allowed)
		)
		(placement
			(enabled no)
			(sheetname "")
		)
		(fill
			(thermal_gap 0.5)
			(thermal_bridge_width 0.5)
			(island_removal_mode 0)
		)
		(polygon
			(pts
				(xy 262.50011 -206.46644) (xy 262.50011 -206.022702) (xy 264.825226 -206.022702) (xy 264.825226 -206.46644)
			)
		)
	)
	(zone
		(layer "F.Cu")
		(hatch none 0.5)
		(connect_pads
			(clearance 0)
		)
		(min_thickness 0.25)
		(keepout
			(tracks allowed)
			(vias allowed)
			(pads allowed)
			(copperpour allowed)
			(footprints allowed)
		)
		(placement
			(enabled no)
			(sheetname "")
		)
		(fill
			(thermal_gap 0.5)
			(thermal_bridge_width 0.5)
			(island_removal_mode 0)
		)
		(polygon
			(pts
				(xy 440.006994 -286.026352) (xy 442.038994 -286.026352) (xy 442.038994 -286.254952) (xy 440.006994 -286.254952)
				(xy 439.87085 -286.254952) (xy 439.82386 -286.254952) (xy 439.82386 -286.026352) (xy 439.87085 -286.026352)
			)
		)
	)
	(zone
		(layer "F.Cu")
		(hatch none 0.5)
		(connect_pads
			(clearance 0)
		)
		(min_thickness 0.25)
		(keepout
			(tracks allowed)
			(vias allowed)
			(pads allowed)
			(copperpour allowed)
			(footprints allowed)
		)
		(placement
			(enabled no)
			(sheetname "")
		)
		(fill
			(thermal_gap 0.5)
			(thermal_bridge_width 0.5)
			(island_removal_mode 0)
		)
		(polygon
			(pts
				(xy 88.58758 -289.042348) (xy 88.8746 -289.042348) (xy 88.90508 -289.011868) (xy 88.90508 -288.384488)
				(xy 88.81872 -288.298128) (xy 88.63076 -288.298128) (xy 88.5571 -288.371788) (xy 88.5571 -289.011868)
			)
		)
	)
	(zone
		(layer "F.Cu")
		(hatch none 0.5)
		(connect_pads
			(clearance 0)
		)
		(min_thickness 0.25)
		(keepout
			(tracks allowed)
			(vias allowed)
			(pads allowed)
			(copperpour allowed)
			(footprints allowed)
		)
		(placement
			(enabled no)
			(sheetname "")
		)
		(fill
			(thermal_gap 0.5)
			(thermal_bridge_width 0.5)
			(island_removal_mode 0)
		)
		(polygon
			(pts
				(xy 195.510658 -227.604828) (xy 195.510658 -227.376228) (xy 197.542658 -227.376228) (xy 197.542658 -227.604828)
			)
		)
	)
	(zone
		(layer "F.Cu")
		(hatch none 0.5)
		(connect_pads
			(clearance 0)
		)
		(min_thickness 0.25)
		(keepout
			(tracks allowed)
			(vias allowed)
			(pads allowed)
			(copperpour allowed)
			(footprints allowed)
		)
		(placement
			(enabled no)
			(sheetname "")
		)
		(fill
			(thermal_gap 0.5)
			(thermal_bridge_width 0.5)
			(island_removal_mode 0)
		)
		(polygon
			(pts
				(xy 195.510658 -265.854942) (xy 195.510658 -265.626342) (xy 197.542658 -265.626342) (xy 197.542658 -265.854942)
			)
		)
	)
	(zone
		(layer "F.Cu")
		(hatch none 0.5)
		(connect_pads
			(clearance 0)
		)
		(min_thickness 0.25)
		(keepout
			(tracks allowed)
			(vias allowed)
			(pads allowed)
			(copperpour allowed)
			(footprints not_allowed)
		)
		(placement
			(enabled no)
			(sheetname "")
		)
		(fill
			(thermal_gap 0.5)
			(thermal_bridge_width 0.5)
			(island_removal_mode 0)
		)
		(polygon
			(pts
				(arc
					(start 95.500444 -435.600094)
					(mid 100.500434 -430.600104)
					(end 105.500424 -435.600094)
				)
				(arc
					(start 105.500424 -435.600094)
					(mid 100.500434 -440.600084)
					(end 95.500444 -435.600094)
				)
			)
		)
	)
	(zone
		(layer "F.Cu")
		(hatch none 0.5)
		(connect_pads
			(clearance 0)
		)
		(min_thickness 0.25)
		(keepout
			(tracks allowed)
			(vias allowed)
			(pads allowed)
			(copperpour allowed)
			(footprints allowed)
		)
		(placement
			(enabled no)
			(sheetname "")
		)
		(fill
			(thermal_gap 0.5)
			(thermal_bridge_width 0.5)
			(island_removal_mode 0)
		)
		(polygon
			(pts
				(xy 409.831794 -210.604862) (xy 409.831794 -210.376262) (xy 411.863794 -210.376262) (xy 411.863794 -210.604862)
			)
		)
	)
	(zone
		(layer "F.Cu")
		(hatch none 0.5)
		(connect_pads
			(clearance 0)
		)
		(min_thickness 0.25)
		(keepout
			(tracks allowed)
			(vias allowed)
			(pads allowed)
			(copperpour allowed)
			(footprints allowed)
		)
		(placement
			(enabled no)
			(sheetname "")
		)
		(fill
			(thermal_gap 0.5)
			(thermal_bridge_width 0.5)
			(island_removal_mode 0)
		)
		(polygon
			(pts
				(xy 428.363126 -247.154954) (xy 428.363126 -246.926354) (xy 430.395126 -246.926354) (xy 430.395126 -247.154954)
			)
		)
	)
	(zone
		(layer "F.Cu")
		(hatch none 0.5)
		(connect_pads
			(clearance 0)
		)
		(min_thickness 0.25)
		(keepout
			(tracks allowed)
			(vias allowed)
			(pads allowed)
			(copperpour allowed)
			(footprints allowed)
		)
		(placement
			(enabled no)
			(sheetname "")
		)
		(fill
			(thermal_gap 0.5)
			(thermal_bridge_width 0.5)
			(island_removal_mode 0)
		)
		(polygon
			(pts
				(xy 41.29151 -233.666538) (xy 41.29151 -233.2228) (xy 43.616626 -233.2228) (xy 43.616626 -233.666538)
			)
		)
	)
	(zone
		(layer "F.Cu")
		(hatch none 0.5)
		(connect_pads
			(clearance 0)
		)
		(min_thickness 0.25)
		(keepout
			(tracks allowed)
			(vias allowed)
			(pads allowed)
			(copperpour allowed)
			(footprints allowed)
		)
		(placement
			(enabled no)
			(sheetname "")
		)
		(fill
			(thermal_gap 0.5)
			(thermal_bridge_width 0.5)
			(island_removal_mode 0)
		)
		(polygon
			(pts
				(xy 311.91708 -210.716622) (xy 311.91708 -210.272884) (xy 314.12688 -210.272884) (xy 314.12688 -210.716622)
			)
		)
	)
	(zone
		(layer "F.Cu")
		(hatch none 0.5)
		(connect_pads
			(clearance 0)
		)
		(min_thickness 0.25)
		(keepout
			(tracks allowed)
			(vias allowed)
			(pads allowed)
			(copperpour allowed)
			(footprints allowed)
		)
		(placement
			(enabled no)
			(sheetname "")
		)
		(fill
			(thermal_gap 0.5)
			(thermal_bridge_width 0.5)
			(island_removal_mode 0)
		)
		(polygon
			(pts
				(xy 59.822842 -218.366594) (xy 59.822842 -217.922856) (xy 62.147958 -217.922856) (xy 62.147958 -218.366594)
			)
		)
	)
	(zone
		(layer "F.Cu")
		(hatch none 0.5)
		(connect_pads
			(clearance 0)
		)
		(min_thickness 0.25)
		(keepout
			(tracks allowed)
			(vias allowed)
			(pads allowed)
			(copperpour allowed)
			(footprints allowed)
		)
		(placement
			(enabled no)
			(sheetname "")
		)
		(fill
			(thermal_gap 0.5)
			(thermal_bridge_width 0.5)
			(island_removal_mode 0)
		)
		(polygon
			(pts
				(xy 176.979326 -245.454932) (xy 176.979326 -245.226332) (xy 179.011326 -245.226332) (xy 179.011326 -245.454932)
			)
		)
	)
	(zone
		(layer "F.Cu")
		(hatch none 0.5)
		(connect_pads
			(clearance 0)
		)
		(min_thickness 0.25)
		(keepout
			(tracks allowed)
			(vias allowed)
			(pads allowed)
			(copperpour allowed)
			(footprints not_allowed)
		)
		(placement
			(enabled no)
			(sheetname "")
		)
		(fill
			(thermal_gap 0.5)
			(thermal_bridge_width 0.5)
			(island_removal_mode 0)
		)
		(polygon
			(pts
				(xy 34.56178 -87.265002) (xy 55.558436 -87.267288) (xy 55.5625 -59.967114) (xy 34.564574 -59.965082)
			)
		)
	)
	(zone
		(layer "F.Cu")
		(hatch none 0.5)
		(connect_pads
			(clearance 0)
		)
		(min_thickness 0.25)
		(keepout
			(tracks allowed)
			(vias allowed)
			(pads allowed)
			(copperpour allowed)
			(footprints not_allowed)
		)
		(placement
			(enabled no)
			(sheetname "")
		)
		(fill
			(thermal_gap 0.5)
			(thermal_bridge_width 0.5)
			(island_removal_mode 0)
		)
		(polygon
			(pts
				(arc
					(start 231.650032 -352.49993)
					(mid 236.650022 -347.49994)
					(end 241.650012 -352.49993)
				)
				(arc
					(start 241.650012 -352.49993)
					(mid 236.650022 -357.49992)
					(end 231.650032 -352.49993)
				)
			)
		)
	)
	(zone
		(layer "F.Cu")
		(hatch none 0.5)
		(connect_pads
			(clearance 0)
		)
		(min_thickness 0.25)
		(keepout
			(tracks allowed)
			(vias allowed)
			(pads allowed)
			(copperpour allowed)
			(footprints allowed)
		)
		(placement
			(enabled no)
			(sheetname "")
		)
		(fill
			(thermal_gap 0.5)
			(thermal_bridge_width 0.5)
			(island_removal_mode 0)
		)
		(polygon
			(pts
				(xy 262.50011 -227.716588) (xy 262.50011 -227.27285) (xy 264.825226 -227.27285) (xy 264.825226 -227.716588)
			)
		)
	)
	(zone
		(layer "F.Cu")
		(hatch none 0.5)
		(connect_pads
			(clearance 0)
		)
		(min_thickness 0.25)
		(keepout
			(tracks allowed)
			(vias allowed)
			(pads allowed)
			(copperpour allowed)
			(footprints allowed)
		)
		(placement
			(enabled no)
			(sheetname "")
		)
		(fill
			(thermal_gap 0.5)
			(thermal_bridge_width 0.5)
			(island_removal_mode 0)
		)
		(polygon
			(pts
				(xy 26.20391 -264.266426) (xy 26.20391 -263.822688) (xy 28.529026 -263.822688) (xy 28.529026 -264.266426)
			)
		)
	)
	(zone
		(layer "F.Cu")
		(hatch none 0.5)
		(connect_pads
			(clearance 0)
		)
		(min_thickness 0.25)
		(keepout
			(tracks allowed)
			(vias allowed)
			(pads allowed)
			(copperpour allowed)
			(footprints allowed)
		)
		(placement
			(enabled no)
			(sheetname "")
		)
		(fill
			(thermal_gap 0.5)
			(thermal_bridge_width 0.5)
			(island_removal_mode 0)
		)
		(polygon
			(pts
				(xy 11.11631 -216.666572) (xy 11.11631 -216.222834) (xy 13.441426 -216.222834) (xy 13.441426 -216.666572)
			)
		)
	)
	(zone
		(layer "F.Cu")
		(hatch none 0.5)
		(connect_pads
			(clearance 0)
		)
		(min_thickness 0.25)
		(keepout
			(tracks allowed)
			(vias allowed)
			(pads allowed)
			(copperpour allowed)
			(footprints allowed)
		)
		(placement
			(enabled no)
			(sheetname "")
		)
		(fill
			(thermal_gap 0.5)
			(thermal_bridge_width 0.5)
			(island_removal_mode 0)
		)
		(polygon
			(pts
				(xy 415.197544 -410.948886) (xy 415.197544 -406.105868) (xy 417.08197 -406.105868) (xy 417.08197 -410.948886)
			)
		)
	)
	(zone
		(layer "F.Cu")
		(hatch none 0.5)
		(connect_pads
			(clearance 0)
		)
		(min_thickness 0.25)
		(keepout
			(tracks allowed)
			(vias allowed)
			(pads allowed)
			(copperpour allowed)
			(footprints allowed)
		)
		(placement
			(enabled no)
			(sheetname "")
		)
		(fill
			(thermal_gap 0.5)
			(thermal_bridge_width 0.5)
			(island_removal_mode 0)
		)
		(polygon
			(pts
				(xy 207.154526 -281.776424) (xy 209.186526 -281.776424) (xy 209.186526 -282.005024) (xy 207.154526 -282.005024)
				(xy 207.018382 -282.005024) (xy 206.971392 -282.005024) (xy 206.971392 -281.776424) (xy 207.018382 -281.776424)
			)
		)
	)
	(zone
		(layer "F.Cu")
		(hatch none 0.5)
		(connect_pads
			(clearance 0)
		)
		(min_thickness 0.25)
		(keepout
			(tracks allowed)
			(vias allowed)
			(pads allowed)
			(copperpour allowed)
			(footprints allowed)
		)
		(placement
			(enabled no)
			(sheetname "")
		)
		(fill
			(thermal_gap 0.5)
			(thermal_bridge_width 0.5)
			(island_removal_mode 0)
		)
		(polygon
			(pts
				(xy 331.285342 -342.847422) (xy 327.749662 -342.847422) (xy 327.749662 -340.764622) (xy 331.285342 -340.764622)
			)
		)
	)
	(zone
		(layer "F.Cu")
		(hatch none 0.5)
		(connect_pads
			(clearance 0)
		)
		(min_thickness 0.25)
		(keepout
			(tracks allowed)
			(vias allowed)
			(pads allowed)
			(copperpour allowed)
			(footprints allowed)
		)
		(placement
			(enabled no)
			(sheetname "")
		)
		(fill
			(thermal_gap 0.5)
			(thermal_bridge_width 0.5)
			(island_removal_mode 0)
		)
		(polygon
			(pts
				(xy 296.20718 -352.064828) (xy 296.20718 -349.169228) (xy 300.57852 -349.169228) (xy 300.57852 -352.064828)
			)
		)
	)
	(zone
		(layer "F.Cu")
		(hatch none 0.5)
		(connect_pads
			(clearance 0)
		)
		(min_thickness 0.25)
		(keepout
			(tracks allowed)
			(vias allowed)
			(pads allowed)
			(copperpour allowed)
			(footprints allowed)
		)
		(placement
			(enabled no)
			(sheetname "")
		)
		(fill
			(thermal_gap 0.5)
			(thermal_bridge_width 0.5)
			(island_removal_mode 0)
		)
		(polygon
			(pts
				(xy 311.86628 -242.968272) (xy 314.17768 -242.968272) (xy 314.17768 -243.857272) (xy 311.86628 -243.857272)
				(xy 311.75198 -243.857272) (xy 311.75198 -242.968272)
			)
		)
	)
	(zone
		(layer "F.Cu")
		(hatch none 0.5)
		(connect_pads
			(clearance 0)
		)
		(min_thickness 0.25)
		(keepout
			(tracks allowed)
			(vias allowed)
			(pads allowed)
			(copperpour allowed)
			(footprints allowed)
		)
		(placement
			(enabled no)
			(sheetname "")
		)
		(fill
			(thermal_gap 0.5)
			(thermal_bridge_width 0.5)
			(island_removal_mode 0)
		)
		(polygon
			(pts
				(xy 210.598258 -314.304934) (xy 210.598258 -314.076334) (xy 212.630258 -314.076334) (xy 212.630258 -314.304934)
			)
		)
	)
	(zone
		(layer "F.Cu")
		(hatch none 0.5)
		(connect_pads
			(clearance 0)
		)
		(min_thickness 0.25)
		(keepout
			(tracks allowed)
			(vias allowed)
			(pads allowed)
			(copperpour allowed)
			(footprints allowed)
		)
		(placement
			(enabled no)
			(sheetname "")
		)
		(fill
			(thermal_gap 0.5)
			(thermal_bridge_width 0.5)
			(island_removal_mode 0)
		)
		(polygon
			(pts
				(xy 413.275526 -292.204902) (xy 413.275526 -291.976302) (xy 415.307526 -291.976302) (xy 415.307526 -292.204902)
			)
		)
	)
	(zone
		(layer "F.Cu")
		(hatch none 0.5)
		(connect_pads
			(clearance 0)
		)
		(min_thickness 0.25)
		(keepout
			(tracks allowed)
			(vias allowed)
			(pads allowed)
			(copperpour allowed)
			(footprints allowed)
		)
		(placement
			(enabled no)
			(sheetname "")
		)
		(fill
			(thermal_gap 0.5)
			(thermal_bridge_width 0.5)
			(island_removal_mode 0)
		)
		(polygon
			(pts
				(xy 424.919394 -239.276382) (xy 426.951394 -239.276382) (xy 426.951394 -239.504982) (xy 424.919394 -239.504982)
				(xy 424.78325 -239.504982) (xy 424.73626 -239.504982) (xy 424.73626 -239.276382) (xy 424.78325 -239.276382)
			)
		)
	)
	(zone
		(layer "F.Cu")
		(hatch none 0.5)
		(connect_pads
			(clearance 0)
		)
		(min_thickness 0.25)
		(keepout
			(tracks allowed)
			(vias allowed)
			(pads allowed)
			(copperpour allowed)
			(footprints allowed)
		)
		(placement
			(enabled no)
			(sheetname "")
		)
		(fill
			(thermal_gap 0.5)
			(thermal_bridge_width 0.5)
			(island_removal_mode 0)
		)
		(polygon
			(pts
				(xy 418.142166 -5.888228) (xy 418.142166 -3.952748) (xy 420.313866 -3.952748) (xy 420.313866 -5.888228)
			)
		)
	)
	(zone
		(layer "F.Cu")
		(hatch none 0.5)
		(connect_pads
			(clearance 0)
		)
		(min_thickness 0.25)
		(keepout
			(tracks allowed)
			(vias allowed)
			(pads allowed)
			(copperpour allowed)
			(footprints allowed)
		)
		(placement
			(enabled no)
			(sheetname "")
		)
		(fill
			(thermal_gap 0.5)
			(thermal_bridge_width 0.5)
			(island_removal_mode 0)
		)
		(polygon
			(pts
				(xy 194.110102 -276.056852) (xy 192.078102 -276.056852) (xy 192.078102 -276.054566) (xy 191.899286 -276.054566)
				(xy 191.899286 -275.81733) (xy 191.762634 -275.680678) (xy 191.757046 -275.680678) (xy 191.718184 -275.641816)
				(xy 191.718184 -275.641308) (xy 191.718184 -275.418296) (xy 191.871854 -275.264626) (xy 194.331082 -275.264626)
				(xy 194.472306 -275.40585) (xy 194.472306 -275.602954) (xy 194.390772 -275.684488) (xy 194.306952 -275.768308)
				(xy 194.306952 -276.056852) (xy 194.293236 -276.056852) (xy 194.246246 -276.056852)
			)
		)
	)
	(zone
		(layer "F.Cu")
		(hatch none 0.5)
		(connect_pads
			(clearance 0)
		)
		(min_thickness 0.25)
		(keepout
			(tracks allowed)
			(vias allowed)
			(pads allowed)
			(copperpour allowed)
			(footprints allowed)
		)
		(placement
			(enabled no)
			(sheetname "")
		)
		(fill
			(thermal_gap 0.5)
			(thermal_bridge_width 0.5)
			(island_removal_mode 0)
		)
		(polygon
			(pts
				(xy 161.891726 -287.954974) (xy 161.891726 -287.726374) (xy 163.923726 -287.726374) (xy 163.923726 -287.954974)
			)
		)
	)
	(zone
		(layer "F.Cu")
		(hatch none 0.5)
		(connect_pads
			(clearance 0)
		)
		(min_thickness 0.25)
		(keepout
			(tracks allowed)
			(vias allowed)
			(pads allowed)
			(copperpour allowed)
			(footprints allowed)
		)
		(placement
			(enabled no)
			(sheetname "")
		)
		(fill
			(thermal_gap 0.5)
			(thermal_bridge_width 0.5)
			(island_removal_mode 0)
		)
		(polygon
			(pts
				(xy 14.560042 -196.266562) (xy 14.560042 -195.822824) (xy 16.885158 -195.822824) (xy 16.885158 -196.266562)
			)
		)
	)
	(zone
		(layer "F.Cu")
		(hatch none 0.5)
		(connect_pads
			(clearance 0)
		)
		(min_thickness 0.25)
		(keepout
			(tracks allowed)
			(vias allowed)
			(pads allowed)
			(copperpour allowed)
			(footprints allowed)
		)
		(placement
			(enabled no)
			(sheetname "")
		)
		(fill
			(thermal_gap 0.5)
			(thermal_bridge_width 0.5)
			(island_removal_mode 0)
		)
		(polygon
			(pts
				(xy 334.1878 -286.606488) (xy 334.47482 -286.606488) (xy 334.5053 -286.576008) (xy 334.5053 -285.948628)
				(xy 334.41894 -285.862268) (xy 334.23098 -285.862268) (xy 334.15732 -285.935928) (xy 334.15732 -286.576008)
			)
		)
	)
	(zone
		(layer "F.Cu")
		(hatch none 0.5)
		(connect_pads
			(clearance 0)
		)
		(min_thickness 0.25)
		(keepout
			(tracks allowed)
			(vias allowed)
			(pads allowed)
			(copperpour allowed)
			(footprints allowed)
		)
		(placement
			(enabled no)
			(sheetname "")
		)
		(fill
			(thermal_gap 0.5)
			(thermal_bridge_width 0.5)
			(island_removal_mode 0)
		)
		(polygon
			(pts
				(xy 63.977012 -261.71652) (xy 63.977012 -261.272782) (xy 66.212212 -261.272782) (xy 66.212212 -261.71652)
			)
		)
	)
	(zone
		(layer "F.Cu")
		(hatch none 0.5)
		(connect_pads
			(clearance 0)
		)
		(min_thickness 0.25)
		(keepout
			(tracks allowed)
			(vias allowed)
			(pads allowed)
			(copperpour allowed)
			(footprints allowed)
		)
		(placement
			(enabled no)
			(sheetname "")
		)
		(fill
			(thermal_gap 0.5)
			(thermal_bridge_width 0.5)
			(island_removal_mode 0)
		)
		(polygon
			(pts
				(xy 157.241494 -316.668404) (xy 215.911176 -316.668404) (xy 216.228168 -316.351412) (xy 216.228168 -258.60629)
				(xy 215.822784 -258.200906) (xy 157.294072 -258.200906) (xy 157.188408 -258.30657) (xy 157.188408 -270.57477)
				(xy 156.991558 -270.77162) (xy 156.991558 -271.801336) (xy 156.991558 -273.100038) (xy 157.188408 -273.296888)
				(xy 157.188408 -274.434046) (xy 156.863034 -274.75942) (xy 156.863034 -278.880824) (xy 157.188408 -279.206198)
				(xy 157.188408 -281.422602) (xy 156.699458 -281.911552) (xy 156.597858 -282.013152) (xy 156.597858 -283.270452)
				(xy 156.699458 -283.372052) (xy 157.188408 -283.861002) (xy 157.188408 -316.615318)
			)
		)
	)
	(zone
		(layer "F.Cu")
		(hatch none 0.5)
		(connect_pads
			(clearance 0)
		)
		(min_thickness 0.25)
		(keepout
			(tracks allowed)
			(vias allowed)
			(pads allowed)
			(copperpour allowed)
			(footprints allowed)
		)
		(placement
			(enabled no)
			(sheetname "")
		)
		(fill
			(thermal_gap 0.5)
			(thermal_bridge_width 0.5)
			(island_removal_mode 0)
		)
		(polygon
			(pts
				(xy 11.11631 -288.06648) (xy 11.11631 -287.622742) (xy 13.441426 -287.622742) (xy 13.441426 -288.06648)
			)
		)
	)
	(zone
		(layer "F.Cu")
		(hatch none 0.5)
		(connect_pads
			(clearance 0)
		)
		(min_thickness 0.25)
		(keepout
			(tracks allowed)
			(vias allowed)
			(pads allowed)
			(copperpour allowed)
			(footprints allowed)
		)
		(placement
			(enabled no)
			(sheetname "")
		)
		(fill
			(thermal_gap 0.5)
			(thermal_bridge_width 0.5)
			(island_removal_mode 0)
		)
		(polygon
			(pts
				(xy 80.668368 -345.159838) (xy 78.920848 -345.159838) (xy 78.920848 -343.224358) (xy 80.668368 -343.224358)
			)
		)
	)
	(zone
		(layer "F.Cu")
		(hatch none 0.5)
		(connect_pads
			(clearance 0)
		)
		(min_thickness 0.25)
		(keepout
			(tracks allowed)
			(vias allowed)
			(pads allowed)
			(copperpour allowed)
			(footprints allowed)
		)
		(placement
			(enabled no)
			(sheetname "")
		)
		(fill
			(thermal_gap 0.5)
			(thermal_bridge_width 0.5)
			(island_removal_mode 0)
		)
		(polygon
			(pts
				(xy 304.319178 -252.727206) (xy 304.319178 -251.922788) (xy 306.644294 -251.922788) (xy 306.644294 -252.727206)
			)
		)
	)
	(zone
		(layer "F.Cu")
		(hatch none 0.5)
		(connect_pads
			(clearance 0)
		)
		(min_thickness 0.25)
		(keepout
			(tracks allowed)
			(vias allowed)
			(pads allowed)
			(copperpour allowed)
			(footprints allowed)
		)
		(placement
			(enabled no)
			(sheetname "")
		)
		(fill
			(thermal_gap 0.5)
			(thermal_bridge_width 0.5)
			(island_removal_mode 0)
		)
		(polygon
			(pts
				(xy 455.094594 -261.376414) (xy 457.126594 -261.376414) (xy 457.126594 -261.605014) (xy 455.094594 -261.605014)
				(xy 454.92797 -261.605014) (xy 454.92797 -261.376414)
			)
		)
	)
	(zone
		(layer "F.Cu")
		(hatch none 0.5)
		(connect_pads
			(clearance 0)
		)
		(min_thickness 0.25)
		(keepout
			(tracks not_allowed)
			(vias allowed)
			(pads allowed)
			(copperpour not_allowed)
			(footprints allowed)
		)
		(placement
			(enabled no)
			(sheetname "")
		)
		(fill
			(thermal_gap 0.5)
			(thermal_bridge_width 0.5)
			(island_removal_mode 0)
		)
		(polygon
			(pts
				(arc
					(start 98.482912 -47.049944)
					(mid 100.383086 -45.14977)
					(end 102.283006 -47.049944)
				)
				(arc
					(start 102.283006 -47.049944)
					(mid 100.383086 -48.949864)
					(end 98.482912 -47.049944)
				)
			)
		)
	)
	(zone
		(layer "F.Cu")
		(hatch none 0.5)
		(connect_pads
			(clearance 0)
		)
		(min_thickness 0.25)
		(keepout
			(tracks allowed)
			(vias allowed)
			(pads allowed)
			(copperpour allowed)
			(footprints allowed)
		)
		(placement
			(enabled no)
			(sheetname "")
		)
		(fill
			(thermal_gap 0.5)
			(thermal_bridge_width 0.5)
			(island_removal_mode 0)
		)
		(polygon
			(pts
				(xy 14.560042 -218.366594) (xy 14.560042 -217.922856) (xy 16.885158 -217.922856) (xy 16.885158 -218.366594)
			)
		)
	)
	(zone
		(layer "F.Cu")
		(hatch none 0.5)
		(connect_pads
			(clearance 0)
		)
		(min_thickness 0.25)
		(keepout
			(tracks allowed)
			(vias allowed)
			(pads allowed)
			(copperpour allowed)
			(footprints not_allowed)
		)
		(placement
			(enabled no)
			(sheetname "")
		)
		(fill
			(thermal_gap 0.5)
			(thermal_bridge_width 0.5)
			(island_removal_mode 0)
		)
		(polygon
			(pts
				(xy 277.71217 -330.091796) (xy 283.81198 -330.091796) (xy 283.81198 -186.09183) (xy 277.71217 -186.09183)
			)
		)
	)
	(zone
		(layer "F.Cu")
		(hatch none 0.5)
		(connect_pads
			(clearance 0)
		)
		(min_thickness 0.25)
		(keepout
			(tracks allowed)
			(vias allowed)
			(pads allowed)
			(copperpour allowed)
			(footprints allowed)
		)
		(placement
			(enabled no)
			(sheetname "")
		)
		(fill
			(thermal_gap 0.5)
			(thermal_bridge_width 0.5)
			(island_removal_mode 0)
		)
		(polygon
			(pts
				(xy 161.891726 -213.155022) (xy 161.891726 -212.926422) (xy 163.923726 -212.926422) (xy 163.923726 -213.155022)
			)
		)
	)
	(zone
		(layer "F.Cu")
		(hatch none 0.5)
		(connect_pads
			(clearance 0)
		)
		(min_thickness 0.25)
		(keepout
			(tracks allowed)
			(vias allowed)
			(pads allowed)
			(copperpour allowed)
			(footprints allowed)
		)
		(placement
			(enabled no)
			(sheetname "")
		)
		(fill
			(thermal_gap 0.5)
			(thermal_bridge_width 0.5)
			(island_removal_mode 0)
		)
		(polygon
			(pts
				(xy 259.056378 -275.316442) (xy 259.056378 -274.872704) (xy 261.381494 -274.872704) (xy 261.381494 -275.316442)
			)
		)
	)
	(zone
		(layer "F.Cu")
		(hatch none 0.5)
		(connect_pads
			(clearance 0)
		)
		(min_thickness 0.25)
		(keepout
			(tracks allowed)
			(vias allowed)
			(pads allowed)
			(copperpour allowed)
			(footprints allowed)
		)
		(placement
			(enabled no)
			(sheetname "")
		)
		(fill
			(thermal_gap 0.5)
			(thermal_bridge_width 0.5)
			(island_removal_mode 0)
		)
		(polygon
			(pts
				(xy 157.791658 -267.554964) (xy 157.791658 -267.326364) (xy 159.823658 -267.326364) (xy 159.823658 -267.554964)
			)
		)
	)
	(zone
		(layer "F.Cu")
		(hatch none 0.5)
		(connect_pads
			(clearance 0)
		)
		(min_thickness 0.25)
		(keepout
			(tracks allowed)
			(vias allowed)
			(pads allowed)
			(copperpour allowed)
			(footprints not_allowed)
		)
		(placement
			(enabled no)
			(sheetname "")
		)
		(fill
			(thermal_gap 0.5)
			(thermal_bridge_width 0.5)
			(island_removal_mode 0)
		)
		(polygon
			(pts
				(arc
					(start 228.650038 -192.499996)
					(mid 236.650022 -184.500012)
					(end 244.650006 -192.499996)
				)
				(arc
					(start 244.650006 -192.499996)
					(mid 236.650022 -200.49998)
					(end 228.650038 -192.499996)
				)
			)
		)
	)
	(zone
		(layer "F.Cu")
		(hatch none 0.5)
		(connect_pads
			(clearance 0)
		)
		(min_thickness 0.25)
		(keepout
			(tracks allowed)
			(vias allowed)
			(pads allowed)
			(copperpour allowed)
			(footprints allowed)
		)
		(placement
			(enabled no)
			(sheetname "")
		)
		(fill
			(thermal_gap 0.5)
			(thermal_bridge_width 0.5)
			(island_removal_mode 0)
		)
		(polygon
			(pts
				(xy 11.11631 -201.366628) (xy 11.11631 -200.92289) (xy 13.441426 -200.92289) (xy 13.441426 -201.366628)
			)
		)
	)
	(zone
		(layer "F.Cu")
		(hatch none 0.5)
		(connect_pads
			(clearance 0)
		)
		(min_thickness 0.25)
		(keepout
			(tracks allowed)
			(vias allowed)
			(pads allowed)
			(copperpour allowed)
			(footprints allowed)
		)
		(placement
			(enabled no)
			(sheetname "")
		)
		(fill
			(thermal_gap 0.5)
			(thermal_bridge_width 0.5)
			(island_removal_mode 0)
		)
		(polygon
			(pts
				(xy 455.094594 -263.076436) (xy 457.126594 -263.076436) (xy 457.126594 -263.305036) (xy 455.094594 -263.305036)
				(xy 454.92797 -263.305036) (xy 454.92797 -263.076436)
			)
		)
	)
	(zone
		(layer "F.Cu")
		(hatch none 0.5)
		(connect_pads
			(clearance 0)
		)
		(min_thickness 0.25)
		(keepout
			(tracks allowed)
			(vias allowed)
			(pads allowed)
			(copperpour allowed)
			(footprints allowed)
		)
		(placement
			(enabled no)
			(sheetname "")
		)
		(fill
			(thermal_gap 0.5)
			(thermal_bridge_width 0.5)
			(island_removal_mode 0)
		)
		(polygon
			(pts
				(xy 41.29151 -282.11653) (xy 41.29151 -281.672792) (xy 43.616626 -281.672792) (xy 43.616626 -282.11653)
			)
		)
	)
	(zone
		(layer "F.Cu")
		(hatch none 0.5)
		(connect_pads
			(clearance 0)
		)
		(min_thickness 0.25)
		(keepout
			(tracks allowed)
			(vias allowed)
			(pads allowed)
			(copperpour allowed)
			(footprints allowed)
		)
		(placement
			(enabled no)
			(sheetname "")
		)
		(fill
			(thermal_gap 0.5)
			(thermal_bridge_width 0.5)
			(island_removal_mode 0)
		)
		(polygon
			(pts
				(xy 458.538326 -248.854976) (xy 458.538326 -248.626376) (xy 460.570326 -248.626376) (xy 460.570326 -248.854976)
			)
		)
	)
	(zone
		(layer "F.Cu")
		(hatch none 0.5)
		(connect_pads
			(clearance 0)
		)
		(min_thickness 0.25)
		(keepout
			(tracks allowed)
			(vias allowed)
			(pads allowed)
			(copperpour allowed)
			(footprints allowed)
		)
		(placement
			(enabled no)
			(sheetname "")
		)
		(fill
			(thermal_gap 0.5)
			(thermal_bridge_width 0.5)
			(island_removal_mode 0)
		)
		(polygon
			(pts
				(xy 14.560042 -233.666538) (xy 14.560042 -233.2228) (xy 16.885158 -233.2228) (xy 16.885158 -233.666538)
			)
		)
	)
	(zone
		(layer "F.Cu")
		(hatch none 0.5)
		(connect_pads
			(clearance 0)
		)
		(min_thickness 0.25)
		(keepout
			(tracks not_allowed)
			(vias allowed)
			(pads allowed)
			(copperpour not_allowed)
			(footprints allowed)
		)
		(placement
			(enabled no)
			(sheetname "")
		)
		(fill
			(thermal_gap 0.5)
			(thermal_bridge_width 0.5)
			(island_removal_mode 0)
		)
		(polygon
			(pts
				(xy 38.39718 -391.99058) (xy 38.39718 -390.87552) (xy 38.62832 -390.87552) (xy 38.62832 -391.99058)
			)
		)
	)
	(zone
		(layer "F.Cu")
		(hatch none 0.5)
		(connect_pads
			(clearance 0)
		)
		(min_thickness 0.25)
		(keepout
			(tracks allowed)
			(vias allowed)
			(pads allowed)
			(copperpour allowed)
			(footprints not_allowed)
		)
		(placement
			(enabled no)
			(sheetname "")
		)
		(fill
			(thermal_gap 0.5)
			(thermal_bridge_width 0.5)
			(island_removal_mode 0)
		)
		(polygon
			(pts
				(arc
					(start 456.460098 -160.50006)
					(mid 461.460088 -155.50007)
					(end 466.460078 -160.50006)
				)
				(arc
					(start 466.460078 -160.50006)
					(mid 461.460088 -165.50005)
					(end 456.460098 -160.50006)
				)
			)
		)
	)
	(zone
		(layer "F.Cu")
		(hatch none 0.5)
		(connect_pads
			(clearance 0)
		)
		(min_thickness 0.25)
		(keepout
			(tracks allowed)
			(vias allowed)
			(pads allowed)
			(copperpour allowed)
			(footprints allowed)
		)
		(placement
			(enabled no)
			(sheetname "")
		)
		(fill
			(thermal_gap 0.5)
			(thermal_bridge_width 0.5)
			(island_removal_mode 0)
		)
		(polygon
			(pts
				(xy 176.979326 -313.226196) (xy 179.011326 -313.226196) (xy 179.011326 -313.454796) (xy 176.979326 -313.454796)
				(xy 176.848008 -313.454796) (xy 176.8221 -313.454796) (xy 176.8221 -313.226196) (xy 176.848008 -313.226196)
			)
		)
	)
	(zone
		(layer "F.Cu")
		(hatch none 0.5)
		(connect_pads
			(clearance 0)
		)
		(min_thickness 0.25)
		(keepout
			(tracks allowed)
			(vias allowed)
			(pads allowed)
			(copperpour allowed)
			(footprints allowed)
		)
		(placement
			(enabled no)
			(sheetname "")
		)
		(fill
			(thermal_gap 0.5)
			(thermal_bridge_width 0.5)
			(island_removal_mode 0)
		)
		(polygon
			(pts
				(xy 304.319178 -216.666572) (xy 304.319178 -216.222834) (xy 306.644294 -216.222834) (xy 306.644294 -216.666572)
			)
		)
	)
	(zone
		(layer "F.Cu")
		(hatch none 0.5)
		(connect_pads
			(clearance 0)
		)
		(min_thickness 0.25)
		(keepout
			(tracks allowed)
			(vias allowed)
			(pads allowed)
			(copperpour allowed)
			(footprints not_allowed)
		)
		(placement
			(enabled no)
			(sheetname "")
		)
		(fill
			(thermal_gap 0.5)
			(thermal_bridge_width 0.5)
			(island_removal_mode 0)
		)
		(polygon
			(pts
				(xy 270.16837 -330.091796) (xy 276.26818 -330.091796) (xy 276.26818 -186.09183) (xy 270.16837 -186.09183)
			)
		)
	)
	(zone
		(layer "F.Cu")
		(hatch none 0.5)
		(connect_pads
			(clearance 0)
		)
		(min_thickness 0.25)
		(keepout
			(tracks allowed)
			(vias allowed)
			(pads allowed)
			(copperpour allowed)
			(footprints allowed)
		)
		(placement
			(enabled no)
			(sheetname "")
		)
		(fill
			(thermal_gap 0.5)
			(thermal_bridge_width 0.5)
			(island_removal_mode 0)
		)
		(polygon
			(pts
				(xy 101.83114 -410.6545) (xy 101.83114 -408.84094) (xy 103.66248 -408.84094) (xy 103.66248 -410.6545)
			)
		)
	)
	(zone
		(layer "F.Cu")
		(hatch none 0.5)
		(connect_pads
			(clearance 0)
		)
		(min_thickness 0.25)
		(keepout
			(tracks allowed)
			(vias allowed)
			(pads allowed)
			(copperpour allowed)
			(footprints allowed)
		)
		(placement
			(enabled no)
			(sheetname "")
		)
		(fill
			(thermal_gap 0.5)
			(thermal_bridge_width 0.5)
			(island_removal_mode 0)
		)
		(polygon
			(pts
				(xy 428.363126 -267.554964) (xy 428.363126 -267.326364) (xy 430.395126 -267.326364) (xy 430.395126 -267.554964)
			)
		)
	)
	(zone
		(layer "F.Cu")
		(hatch none 0.5)
		(connect_pads
			(clearance 0)
		)
		(min_thickness 0.25)
		(keepout
			(tracks allowed)
			(vias allowed)
			(pads allowed)
			(copperpour allowed)
			(footprints allowed)
		)
		(placement
			(enabled no)
			(sheetname "")
		)
		(fill
			(thermal_gap 0.5)
			(thermal_bridge_width 0.5)
			(island_removal_mode 0)
		)
		(polygon
			(pts
				(xy 292.67531 -203.06665) (xy 292.67531 -202.622912) (xy 295.000426 -202.622912) (xy 295.000426 -203.06665)
			)
		)
	)
	(zone
		(layer "F.Cu")
		(hatch none 0.5)
		(connect_pads
			(clearance 0)
		)
		(min_thickness 0.25)
		(keepout
			(tracks not_allowed)
			(vias allowed)
			(pads allowed)
			(copperpour not_allowed)
			(footprints allowed)
		)
		(placement
			(enabled no)
			(sheetname "")
		)
		(fill
			(thermal_gap 0.5)
			(thermal_bridge_width 0.5)
			(island_removal_mode 0)
		)
		(polygon
			(pts
				(arc
					(start 50.824892 -66.060828)
					(mid 45.062902 -60.298838)
					(end 39.300912 -66.060828)
				)
				(arc
					(start 39.300912 -74.760836)
					(mid 45.062902 -80.522826)
					(end 50.824892 -74.760836)
				)
			)
		)
	)
	(zone
		(layer "F.Cu")
		(hatch none 0.5)
		(connect_pads
			(clearance 0)
		)
		(min_thickness 0.25)
		(keepout
			(tracks allowed)
			(vias allowed)
			(pads allowed)
			(copperpour allowed)
			(footprints allowed)
		)
		(placement
			(enabled no)
			(sheetname "")
		)
		(fill
			(thermal_gap 0.5)
			(thermal_bridge_width 0.5)
			(island_removal_mode 0)
		)
		(polygon
			(pts
				(xy 409.831794 -201.254868) (xy 409.831794 -201.026268) (xy 411.863794 -201.026268) (xy 411.863794 -201.254868)
			)
		)
	)
	(zone
		(layer "F.Cu")
		(hatch none 0.5)
		(connect_pads
			(clearance 0)
		)
		(min_thickness 0.25)
		(keepout
			(tracks allowed)
			(vias allowed)
			(pads allowed)
			(copperpour allowed)
			(footprints allowed)
		)
		(placement
			(enabled no)
			(sheetname "")
		)
		(fill
			(thermal_gap 0.5)
			(thermal_bridge_width 0.5)
			(island_removal_mode 0)
		)
		(polygon
			(pts
				(xy 197.553834 -236.956854) (xy 195.521834 -236.956854) (xy 195.521834 -236.954568) (xy 195.343018 -236.954568)
				(xy 195.343018 -236.717332) (xy 195.206366 -236.58068) (xy 195.200778 -236.58068) (xy 195.161916 -236.541818)
				(xy 195.161916 -236.54131) (xy 195.161916 -236.318298) (xy 195.315586 -236.164628) (xy 197.774814 -236.164628)
				(xy 197.916038 -236.305852) (xy 197.916038 -236.502956) (xy 197.834504 -236.58449) (xy 197.750684 -236.66831)
				(xy 197.750684 -236.956854) (xy 197.736968 -236.956854) (xy 197.689978 -236.956854)
			)
		)
	)
	(zone
		(layer "F.Cu")
		(hatch none 0.5)
		(connect_pads
			(clearance 0)
		)
		(min_thickness 0.25)
		(keepout
			(tracks allowed)
			(vias allowed)
			(pads allowed)
			(copperpour allowed)
			(footprints allowed)
		)
		(placement
			(enabled no)
			(sheetname "")
		)
		(fill
			(thermal_gap 0.5)
			(thermal_bridge_width 0.5)
			(island_removal_mode 0)
		)
		(polygon
			(pts
				(xy 41.29151 -203.916534) (xy 41.29151 -203.472796) (xy 43.616626 -203.472796) (xy 43.616626 -203.916534)
			)
		)
	)
	(zone
		(layer "F.Cu")
		(hatch none 0.5)
		(connect_pads
			(clearance 0)
		)
		(min_thickness 0.25)
		(keepout
			(tracks allowed)
			(vias allowed)
			(pads allowed)
			(copperpour allowed)
			(footprints allowed)
		)
		(placement
			(enabled no)
			(sheetname "")
		)
		(fill
			(thermal_gap 0.5)
			(thermal_bridge_width 0.5)
			(island_removal_mode 0)
		)
		(polygon
			(pts
				(xy 259.056378 -294.866568) (xy 259.056378 -294.42283) (xy 261.381494 -294.42283) (xy 261.381494 -294.866568)
			)
		)
	)
	(zone
		(layer "F.Cu")
		(hatch none 0.5)
		(connect_pads
			(clearance 0)
		)
		(min_thickness 0.25)
		(keepout
			(tracks allowed)
			(vias allowed)
			(pads allowed)
			(copperpour allowed)
			(footprints not_allowed)
		)
		(placement
			(enabled no)
			(sheetname "")
		)
		(fill
			(thermal_gap 0.5)
			(thermal_bridge_width 0.5)
			(island_removal_mode 0)
		)
		(polygon
			(pts
				(xy 2.999994 -374.753886) (xy 22.538182 -374.753886) (xy 22.540468 -350.763586)
				(arc
					(start 14.291564 -350.763586)
					(mid 10.340008 -352.700009)
					(end 6.388354 -350.763586)
				)
				(xy 2.999994 -350.763586)
			)
		)
	)
	(zone
		(layer "F.Cu")
		(hatch none 0.5)
		(connect_pads
			(clearance 0)
		)
		(min_thickness 0.25)
		(keepout
			(tracks allowed)
			(vias allowed)
			(pads allowed)
			(copperpour allowed)
			(footprints allowed)
		)
		(placement
			(enabled no)
			(sheetname "")
		)
		(fill
			(thermal_gap 0.5)
			(thermal_bridge_width 0.5)
			(island_removal_mode 0)
		)
		(polygon
			(pts
				(xy 192.066926 -229.07625) (xy 194.098926 -229.07625) (xy 194.098926 -229.30485) (xy 192.066926 -229.30485)
				(xy 191.935608 -229.30485) (xy 191.9097 -229.30485) (xy 191.9097 -229.07625) (xy 191.935608 -229.07625)
			)
		)
	)
	(zone
		(layer "F.Cu")
		(hatch none 0.5)
		(connect_pads
			(clearance 0)
		)
		(min_thickness 0.25)
		(keepout
			(tracks allowed)
			(vias allowed)
			(pads allowed)
			(copperpour allowed)
			(footprints allowed)
		)
		(placement
			(enabled no)
			(sheetname "")
		)
		(fill
			(thermal_gap 0.5)
			(thermal_bridge_width 0.5)
			(island_removal_mode 0)
		)
		(polygon
			(pts
				(xy 458.538326 -217.40495) (xy 458.538326 -217.17635) (xy 460.570326 -217.17635) (xy 460.570326 -217.40495)
			)
		)
	)
	(zone
		(layer "F.Cu")
		(hatch none 0.5)
		(connect_pads
			(clearance 0)
		)
		(min_thickness 0.25)
		(keepout
			(tracks allowed)
			(vias allowed)
			(pads allowed)
			(copperpour allowed)
			(footprints allowed)
		)
		(placement
			(enabled no)
			(sheetname "")
		)
		(fill
			(thermal_gap 0.5)
			(thermal_bridge_width 0.5)
			(island_removal_mode 0)
		)
		(polygon
			(pts
				(xy 455.094594 -235.026454) (xy 457.126594 -235.026454) (xy 457.126594 -235.255054) (xy 455.094594 -235.255054)
				(xy 454.95845 -235.255054) (xy 454.91146 -235.255054) (xy 454.91146 -235.026454) (xy 454.95845 -235.026454)
			)
		)
	)
	(zone
		(layer "F.Cu")
		(hatch none 0.5)
		(connect_pads
			(clearance 0)
		)
		(min_thickness 0.25)
		(keepout
			(tracks allowed)
			(vias allowed)
			(pads allowed)
			(copperpour allowed)
			(footprints allowed)
		)
		(placement
			(enabled no)
			(sheetname "")
		)
		(fill
			(thermal_gap 0.5)
			(thermal_bridge_width 0.5)
			(island_removal_mode 0)
		)
		(polygon
			(pts
				(xy 443.450726 -269.254986) (xy 443.450726 -269.026386) (xy 445.482726 -269.026386) (xy 445.482726 -269.254986)
			)
		)
	)
	(zone
		(layer "F.Cu")
		(hatch none 0.5)
		(connect_pads
			(clearance 0)
		)
		(min_thickness 0.25)
		(keepout
			(tracks allowed)
			(vias allowed)
			(pads allowed)
			(copperpour allowed)
			(footprints allowed)
		)
		(placement
			(enabled no)
			(sheetname "")
		)
		(fill
			(thermal_gap 0.5)
			(thermal_bridge_width 0.5)
			(island_removal_mode 0)
		)
		(polygon
			(pts
				(xy 292.67531 -252.366526) (xy 292.67531 -251.922788) (xy 295.000426 -251.922788) (xy 295.000426 -252.366526)
			)
		)
	)
	(zone
		(layer "F.Cu")
		(hatch none 0.5)
		(connect_pads
			(clearance 0)
		)
		(min_thickness 0.25)
		(keepout
			(tracks allowed)
			(vias allowed)
			(pads allowed)
			(copperpour allowed)
			(footprints allowed)
		)
		(placement
			(enabled no)
			(sheetname "")
		)
		(fill
			(thermal_gap 0.5)
			(thermal_bridge_width 0.5)
			(island_removal_mode 0)
		)
		(polygon
			(pts
				(xy 277.58771 -198.816468) (xy 277.58771 -198.37273) (xy 279.912826 -198.37273) (xy 279.912826 -198.816468)
			)
		)
	)
	(zone
		(layer "F.Cu")
		(hatch none 0.5)
		(connect_pads
			(clearance 0)
		)
		(min_thickness 0.25)
		(keepout
			(tracks allowed)
			(vias allowed)
			(pads allowed)
			(copperpour allowed)
			(footprints allowed)
		)
		(placement
			(enabled no)
			(sheetname "")
		)
		(fill
			(thermal_gap 0.5)
			(thermal_bridge_width 0.5)
			(island_removal_mode 0)
		)
		(polygon
			(pts
				(xy 289.231578 -289.766502) (xy 289.231578 -289.322764) (xy 291.556694 -289.322764) (xy 291.556694 -289.766502)
			)
		)
	)
	(zone
		(layer "F.Cu")
		(hatch none 0.5)
		(connect_pads
			(clearance 0)
		)
		(min_thickness 0.25)
		(keepout
			(tracks allowed)
			(vias allowed)
			(pads allowed)
			(copperpour allowed)
			(footprints allowed)
		)
		(placement
			(enabled no)
			(sheetname "")
		)
		(fill
			(thermal_gap 0.5)
			(thermal_bridge_width 0.5)
			(island_removal_mode 0)
		)
		(polygon
			(pts
				(xy 372.312184 -410.948886) (xy 372.312184 -406.105868) (xy 374.19661 -406.105868) (xy 374.19661 -410.948886)
			)
		)
	)
	(zone
		(layer "F.Cu")
		(hatch none 0.5)
		(connect_pads
			(clearance 0)
		)
		(min_thickness 0.25)
		(keepout
			(tracks allowed)
			(vias allowed)
			(pads allowed)
			(copperpour allowed)
			(footprints allowed)
		)
		(placement
			(enabled no)
			(sheetname "")
		)
		(fill
			(thermal_gap 0.5)
			(thermal_bridge_width 0.5)
			(island_removal_mode 0)
		)
		(polygon
			(pts
				(xy 344.052906 -332.908402) (xy 342.236806 -332.908402) (xy 342.236806 -331.529182) (xy 344.052906 -331.529182)
			)
		)
	)
	(zone
		(layer "F.Cu")
		(hatch none 0.5)
		(connect_pads
			(clearance 0)
		)
		(min_thickness 0.25)
		(keepout
			(tracks allowed)
			(vias allowed)
			(pads allowed)
			(copperpour allowed)
			(footprints allowed)
		)
		(placement
			(enabled no)
			(sheetname "")
		)
		(fill
			(thermal_gap 0.5)
			(thermal_bridge_width 0.5)
			(island_removal_mode 0)
		)
		(polygon
			(pts
				(xy 210.598258 -220.804994) (xy 210.598258 -220.576394) (xy 212.630258 -220.576394) (xy 212.630258 -220.804994)
			)
		)
	)
	(zone
		(layer "F.Cu")
		(hatch none 0.5)
		(connect_pads
			(clearance 0)
		)
		(min_thickness 0.25)
		(keepout
			(tracks allowed)
			(vias allowed)
			(pads allowed)
			(copperpour allowed)
			(footprints allowed)
		)
		(placement
			(enabled no)
			(sheetname "")
		)
		(fill
			(thermal_gap 0.5)
			(thermal_bridge_width 0.5)
			(island_removal_mode 0)
		)
		(polygon
			(pts
				(xy 405.731726 -205.504796) (xy 405.731726 -205.276196) (xy 407.763726 -205.276196) (xy 407.763726 -205.504796)
			)
		)
	)
	(zone
		(layer "F.Cu")
		(hatch none 0.5)
		(connect_pads
			(clearance 0)
		)
		(min_thickness 0.25)
		(keepout
			(tracks not_allowed)
			(vias allowed)
			(pads allowed)
			(copperpour not_allowed)
			(footprints allowed)
		)
		(placement
			(enabled no)
			(sheetname "")
		)
		(fill
			(thermal_gap 0.5)
			(thermal_bridge_width 0.5)
			(island_removal_mode 0)
		)
		(polygon
			(pts
				(arc
					(start 384.969766 -206.024988)
					(mid 382.874774 -208.11998)
					(end 380.779782 -206.024988)
				)
				(arc
					(start 380.779782 -206.024988)
					(mid 382.874774 -203.929996)
					(end 384.969766 -206.024988)
				)
			)
		)
	)
	(zone
		(layer "F.Cu")
		(hatch none 0.5)
		(connect_pads
			(clearance 0)
		)
		(min_thickness 0.25)
		(keepout
			(tracks allowed)
			(vias allowed)
			(pads allowed)
			(copperpour allowed)
			(footprints allowed)
		)
		(placement
			(enabled no)
			(sheetname "")
		)
		(fill
			(thermal_gap 0.5)
			(thermal_bridge_width 0.5)
			(island_removal_mode 0)
		)
		(polygon
			(pts
				(xy 44.735242 -281.266646) (xy 44.735242 -280.822908) (xy 47.060358 -280.822908) (xy 47.060358 -281.266646)
			)
		)
	)
	(zone
		(layer "F.Cu")
		(hatch none 0.5)
		(connect_pads
			(clearance 0)
		)
		(min_thickness 0.25)
		(keepout
			(tracks allowed)
			(vias allowed)
			(pads allowed)
			(copperpour allowed)
			(footprints allowed)
		)
		(placement
			(enabled no)
			(sheetname "")
		)
		(fill
			(thermal_gap 0.5)
			(thermal_bridge_width 0.5)
			(island_removal_mode 0)
		)
		(polygon
			(pts
				(xy 289.231578 -303.366424) (xy 289.231578 -302.922686) (xy 291.556694 -302.922686) (xy 291.556694 -303.366424)
			)
		)
	)
	(zone
		(layer "F.Cu")
		(hatch none 0.5)
		(connect_pads
			(clearance 0)
		)
		(min_thickness 0.25)
		(keepout
			(tracks allowed)
			(vias allowed)
			(pads allowed)
			(copperpour allowed)
			(footprints allowed)
		)
		(placement
			(enabled no)
			(sheetname "")
		)
		(fill
			(thermal_gap 0.5)
			(thermal_bridge_width 0.5)
			(island_removal_mode 0)
		)
		(polygon
			(pts
				(xy 14.560042 -199.666606) (xy 14.560042 -199.222868) (xy 16.885158 -199.222868) (xy 16.885158 -199.666606)
			)
		)
	)
	(zone
		(layer "F.Cu")
		(hatch none 0.5)
		(connect_pads
			(clearance 0)
		)
		(min_thickness 0.25)
		(keepout
			(tracks not_allowed)
			(vias allowed)
			(pads allowed)
			(copperpour not_allowed)
			(footprints allowed)
		)
		(placement
			(enabled no)
			(sheetname "")
		)
		(fill
			(thermal_gap 0.5)
			(thermal_bridge_width 0.5)
			(island_removal_mode 0)
		)
		(polygon
			(pts
				(xy 95.195644 -335.338928) (xy 95.195644 -334.340708) (xy 94.953328 -334.340708) (xy 94.953328 -335.435448)
				(xy 95.099124 -335.435448)
			)
		)
	)
	(zone
		(layer "F.Cu")
		(hatch none 0.5)
		(connect_pads
			(clearance 0)
		)
		(min_thickness 0.25)
		(keepout
			(tracks allowed)
			(vias allowed)
			(pads allowed)
			(copperpour allowed)
			(footprints allowed)
		)
		(placement
			(enabled no)
			(sheetname "")
		)
		(fill
			(thermal_gap 0.5)
			(thermal_bridge_width 0.5)
			(island_removal_mode 0)
		)
		(polygon
			(pts
				(xy 428.363126 -216.554812) (xy 428.363126 -216.326212) (xy 430.395126 -216.326212) (xy 430.395126 -216.554812)
			)
		)
	)
	(zone
		(layer "F.Cu")
		(hatch none 0.5)
		(connect_pads
			(clearance 0)
		)
		(min_thickness 0.25)
		(keepout
			(tracks allowed)
			(vias allowed)
			(pads allowed)
			(copperpour allowed)
			(footprints allowed)
		)
		(placement
			(enabled no)
			(sheetname "")
		)
		(fill
			(thermal_gap 0.5)
			(thermal_bridge_width 0.5)
			(island_removal_mode 0)
		)
		(polygon
			(pts
				(xy 11.11631 -289.766502) (xy 11.11631 -289.322764) (xy 13.441426 -289.322764) (xy 13.441426 -289.766502)
			)
		)
	)
	(zone
		(layer "F.Cu")
		(hatch none 0.5)
		(connect_pads
			(clearance 0)
		)
		(min_thickness 0.25)
		(keepout
			(tracks allowed)
			(vias allowed)
			(pads allowed)
			(copperpour allowed)
			(footprints allowed)
		)
		(placement
			(enabled no)
			(sheetname "")
		)
		(fill
			(thermal_gap 0.5)
			(thermal_bridge_width 0.5)
			(island_removal_mode 0)
		)
		(polygon
			(pts
				(xy 106.22026 -361.206288) (xy 106.22026 -356.469188) (xy 110.93196 -356.469188) (xy 110.93196 -361.206288)
			)
		)
	)
	(zone
		(layer "F.Cu")
		(hatch none 0.5)
		(connect_pads
			(clearance 0)
		)
		(min_thickness 0.25)
		(keepout
			(tracks allowed)
			(vias allowed)
			(pads allowed)
			(copperpour allowed)
			(footprints allowed)
		)
		(placement
			(enabled no)
			(sheetname "")
		)
		(fill
			(thermal_gap 0.5)
			(thermal_bridge_width 0.5)
			(island_removal_mode 0)
		)
		(polygon
			(pts
				(xy 390.745218 -9.311386) (xy 390.745218 -7.375906) (xy 392.78306 -7.375906) (xy 392.78306 -9.311386)
			)
		)
	)
	(zone
		(layer "F.Cu")
		(hatch none 0.5)
		(connect_pads
			(clearance 0)
		)
		(min_thickness 0.25)
		(keepout
			(tracks allowed)
			(vias allowed)
			(pads allowed)
			(copperpour allowed)
			(footprints allowed)
		)
		(placement
			(enabled no)
			(sheetname "")
		)
		(fill
			(thermal_gap 0.5)
			(thermal_bridge_width 0.5)
			(island_removal_mode 0)
		)
		(polygon
			(pts
				(xy 375.046748 -335.09966) (xy 375.046748 -339.10524) (xy 375.526808 -339.5853) (xy 377.591828 -339.5853)
				(xy 377.863608 -339.31352) (xy 377.863608 -337.45932) (xy 378.115068 -337.20786) (xy 380.035308 -337.20786)
				(xy 380.451868 -336.7913) (xy 380.451868 -335.30032) (xy 379.804168 -334.65262) (xy 375.493788 -334.65262)
			)
		)
	)
	(zone
		(layer "F.Cu")
		(hatch none 0.5)
		(connect_pads
			(clearance 0)
		)
		(min_thickness 0.25)
		(keepout
			(tracks allowed)
			(vias allowed)
			(pads allowed)
			(copperpour allowed)
			(footprints allowed)
		)
		(placement
			(enabled no)
			(sheetname "")
		)
		(fill
			(thermal_gap 0.5)
			(thermal_bridge_width 0.5)
			(island_removal_mode 0)
		)
		(polygon
			(pts
				(xy 274.143978 -269.366492) (xy 274.143978 -268.922754) (xy 276.469094 -268.922754) (xy 276.469094 -269.366492)
			)
		)
	)
	(zone
		(layer "F.Cu")
		(hatch none 0.5)
		(connect_pads
			(clearance 0)
		)
		(min_thickness 0.25)
		(keepout
			(tracks allowed)
			(vias allowed)
			(pads allowed)
			(copperpour allowed)
			(footprints allowed)
		)
		(placement
			(enabled no)
			(sheetname "")
		)
		(fill
			(thermal_gap 0.5)
			(thermal_bridge_width 0.5)
			(island_removal_mode 0)
		)
		(polygon
			(pts
				(xy 388.014464 -257.549904) (xy 389.926576 -259.461762) (xy 390.111742 -259.646928) (xy 390.18464 -259.646928)
				(xy 392.48842 -261.950708) (xy 392.68654 -261.950708) (xy 393.35202 -261.285228) (xy 393.35202 -261.135368)
				(xy 393.35202 -261.079488) (xy 394.2461 -260.185408) (xy 394.2461 -260.063488) (xy 394.68806 -259.621528)
				(xy 395.09446 -259.621528) (xy 395.41958 -259.296408) (xy 395.80058 -259.296408) (xy 396.88008 -258.216908)
				(xy 396.89913 -258.197858) (xy 396.89913 -258.162298) (xy 396.71498 -257.978148) (xy 393.48918 -257.978148)
				(xy 393.38758 -257.876548) (xy 393.38758 -256.695448) (xy 393.37234 -256.680208) (xy 393.29106 -256.680208)
				(xy 393.264644 -256.653792) (xy 393.26312 -256.652268) (xy 393.26312 -255.974088) (xy 392.64844 -255.974088)
				(xy 391.98169 -255.307338) (xy 391.94486 -255.270508) (xy 391.94486 -255.196848) (xy 392.4427 -254.699008)
				(xy 394.296138 -254.699008) (xy 394.400278 -254.594868) (xy 394.400278 -254.01143) (xy 394.304012 -253.915164)
				(xy 393.633706 -253.915164) (xy 393.570206 -253.915164) (xy 393.262612 -253.915164) (xy 393.148566 -253.801118)
				(xy 392.562588 -253.21514) (xy 391.959592 -253.21514) (xy 391.451084 -252.706632) (xy 391.451084 -251.743464)
				(xy 391.451084 -251.29617) (xy 388.364984 -251.296424) (xy 388.11708 -251.04852) (xy 384.68427 -251.04852)
				(xy 384.499358 -250.863608) (xy 384.081274 -250.863608) (xy 383.655316 -250.43765) (xy 383.655316 -250.107958)
				(xy 383.502662 -249.955304) (xy 380.589028 -249.955304) (xy 380.48438 -250.059952) (xy 380.48438 -250.242832)
				(xy 380.534672 -250.242832) (xy 380.936246 -250.644406) (xy 381.248412 -250.8631) (xy 382.852676 -251.705618)
				(xy 383.297176 -251.900944) (xy 383.360676 -251.940822) (xy 383.360676 -252.153674) (xy 383.41173 -252.204728)
				(xy 383.929128 -252.521212) (xy 384.47472 -252.654562) (xy 384.5052 -252.685042) (xy 384.5052 -252.854968)
				(xy 384.781552 -253.13132) (xy 384.831336 -253.13132) (xy 386.523484 -253.13132) (xy 388.41934 -253.527814)
				(xy 388.43712 -253.545594) (xy 388.43712 -253.844298) (xy 388.40791 -253.873508) (xy 388.40791 -253.910592)
				(xy 388.469378 -253.97206) (xy 388.588504 -253.97206) (xy 388.884922 -254.268478) (xy 388.884922 -254.533908)
				(xy 388.835646 -254.583184) (xy 388.327646 -254.583184) (xy 388.314184 -254.596646) (xy 388.314184 -255.411732)
				(xy 388.187184 -255.538732) (xy 388.042658 -255.538732) (xy 387.91769 -255.6637) (xy 387.91769 -255.852168)
				(xy 388.014464 -255.948942)
			)
		)
	)
	(zone
		(layer "F.Cu")
		(hatch none 0.5)
		(connect_pads
			(clearance 0)
		)
		(min_thickness 0.25)
		(keepout
			(tracks allowed)
			(vias allowed)
			(pads allowed)
			(copperpour allowed)
			(footprints allowed)
		)
		(placement
			(enabled no)
			(sheetname "")
		)
		(fill
			(thermal_gap 0.5)
			(thermal_bridge_width 0.5)
			(island_removal_mode 0)
		)
		(polygon
			(pts
				(xy 157.791658 -314.304934) (xy 157.791658 -314.076334) (xy 159.823658 -314.076334) (xy 159.823658 -314.304934)
			)
		)
	)
	(zone
		(layer "F.Cu")
		(hatch none 0.5)
		(connect_pads
			(clearance 0)
		)
		(min_thickness 0.25)
		(keepout
			(tracks allowed)
			(vias allowed)
			(pads allowed)
			(copperpour allowed)
			(footprints allowed)
		)
		(placement
			(enabled no)
			(sheetname "")
		)
		(fill
			(thermal_gap 0.5)
			(thermal_bridge_width 0.5)
			(island_removal_mode 0)
		)
		(polygon
			(pts
				(xy 277.58771 -245.566438) (xy 277.58771 -245.1227) (xy 279.912826 -245.1227) (xy 279.912826 -245.566438)
			)
		)
	)
	(zone
		(layer "F.Cu")
		(hatch none 0.5)
		(connect_pads
			(clearance 0)
		)
		(min_thickness 0.25)
		(keepout
			(tracks allowed)
			(vias allowed)
			(pads allowed)
			(copperpour allowed)
			(footprints allowed)
		)
		(placement
			(enabled no)
			(sheetname "")
		)
		(fill
			(thermal_gap 0.5)
			(thermal_bridge_width 0.5)
			(island_removal_mode 0)
		)
		(polygon
			(pts
				(xy 84.227162 -229.313486) (xy 84.430108 -229.516432) (xy 84.473288 -229.516432) (xy 84.917026 -229.072694)
				(xy 84.917026 -228.95052) (xy 84.78393 -228.817678) (xy 84.67979 -228.817678) (xy 84.227162 -229.270306)
			)
		)
	)
	(zone
		(layer "F.Cu")
		(hatch none 0.5)
		(connect_pads
			(clearance 0)
		)
		(min_thickness 0.25)
		(keepout
			(tracks allowed)
			(vias allowed)
			(pads allowed)
			(copperpour allowed)
			(footprints allowed)
		)
		(placement
			(enabled no)
			(sheetname "")
		)
		(fill
			(thermal_gap 0.5)
			(thermal_bridge_width 0.5)
			(island_removal_mode 0)
		)
		(polygon
			(pts
				(xy 289.231578 -252.366526) (xy 289.231578 -251.922788) (xy 291.556694 -251.922788) (xy 291.556694 -252.366526)
				(xy 291.556694 -252.888496) (xy 289.231578 -252.888496)
			)
		)
	)
	(zone
		(layer "F.Cu")
		(hatch none 0.5)
		(connect_pads
			(clearance 0)
		)
		(min_thickness 0.25)
		(keepout
			(tracks allowed)
			(vias allowed)
			(pads allowed)
			(copperpour allowed)
			(footprints allowed)
		)
		(placement
			(enabled no)
			(sheetname "")
		)
		(fill
			(thermal_gap 0.5)
			(thermal_bridge_width 0.5)
			(island_removal_mode 0)
		)
		(polygon
			(pts
				(xy 443.450726 -214.85479) (xy 443.450726 -214.62619) (xy 445.482726 -214.62619) (xy 445.482726 -214.85479)
			)
		)
	)
	(zone
		(layer "F.Cu")
		(hatch none 0.5)
		(connect_pads
			(clearance 0)
		)
		(min_thickness 0.25)
		(keepout
			(tracks allowed)
			(vias allowed)
			(pads allowed)
			(copperpour allowed)
			(footprints allowed)
		)
		(placement
			(enabled no)
			(sheetname "")
		)
		(fill
			(thermal_gap 0.5)
			(thermal_bridge_width 0.5)
			(island_removal_mode 0)
		)
		(polygon
			(pts
				(xy 440.006994 -209.75701) (xy 442.038994 -209.75701) (xy 442.038994 -209.52841) (xy 440.006994 -209.52841)
				(xy 439.875676 -209.52841) (xy 439.849768 -209.52841) (xy 439.849768 -209.75701) (xy 439.875676 -209.75701)
			)
		)
	)
	(zone
		(layer "F.Cu")
		(hatch none 0.5)
		(connect_pads
			(clearance 0)
		)
		(min_thickness 0.25)
		(keepout
			(tracks allowed)
			(vias allowed)
			(pads allowed)
			(copperpour allowed)
			(footprints allowed)
		)
		(placement
			(enabled no)
			(sheetname "")
		)
		(fill
			(thermal_gap 0.5)
			(thermal_bridge_width 0.5)
			(island_removal_mode 0)
		)
		(polygon
			(pts
				(xy 292.67531 -311.866534) (xy 292.67531 -311.422796) (xy 295.000426 -311.422796) (xy 295.000426 -311.866534)
			)
		)
	)
	(zone
		(layer "F.Cu")
		(hatch none 0.5)
		(connect_pads
			(clearance 0)
		)
		(min_thickness 0.25)
		(keepout
			(tracks allowed)
			(vias allowed)
			(pads allowed)
			(copperpour allowed)
			(footprints allowed)
		)
		(placement
			(enabled no)
			(sheetname "")
		)
		(fill
			(thermal_gap 0.5)
			(thermal_bridge_width 0.5)
			(island_removal_mode 0)
		)
		(polygon
			(pts
				(xy 86.70036 -287.335468) (xy 86.98738 -287.335468) (xy 87.01786 -287.304988) (xy 87.01786 -286.677608)
				(xy 86.9315 -286.591248) (xy 86.74354 -286.591248) (xy 86.66988 -286.664908) (xy 86.66988 -287.304988)
			)
		)
	)
	(zone
		(layer "F.Cu")
		(hatch none 0.5)
		(connect_pads
			(clearance 0)
		)
		(min_thickness 0.25)
		(keepout
			(tracks allowed)
			(vias allowed)
			(pads allowed)
			(copperpour allowed)
			(footprints allowed)
		)
		(placement
			(enabled no)
			(sheetname "")
		)
		(fill
			(thermal_gap 0.5)
			(thermal_bridge_width 0.5)
			(island_removal_mode 0)
		)
		(polygon
			(pts
				(xy 431.73904 -9.657588) (xy 431.73904 -5.867908) (xy 433.61356 -5.867908) (xy 433.61356 -9.657588)
			)
		)
	)
	(zone
		(layer "F.Cu")
		(hatch none 0.5)
		(connect_pads
			(clearance 0)
		)
		(min_thickness 0.25)
		(keepout
			(tracks allowed)
			(vias allowed)
			(pads allowed)
			(copperpour allowed)
			(footprints allowed)
		)
		(placement
			(enabled no)
			(sheetname "")
		)
		(fill
			(thermal_gap 0.5)
			(thermal_bridge_width 0.5)
			(island_removal_mode 0)
		)
		(polygon
			(pts
				(xy 176.979326 -295.376346) (xy 179.011326 -295.376346) (xy 179.011326 -295.604946) (xy 176.979326 -295.604946)
				(xy 176.843182 -295.604946) (xy 176.796192 -295.604946) (xy 176.796192 -295.376346) (xy 176.843182 -295.376346)
			)
		)
	)
	(zone
		(layer "F.Cu")
		(hatch none 0.5)
		(connect_pads
			(clearance 0)
		)
		(min_thickness 0.25)
		(keepout
			(tracks allowed)
			(vias allowed)
			(pads allowed)
			(copperpour allowed)
			(footprints allowed)
		)
		(placement
			(enabled no)
			(sheetname "")
		)
		(fill
			(thermal_gap 0.5)
			(thermal_bridge_width 0.5)
			(island_removal_mode 0)
		)
		(polygon
			(pts
				(xy 59.822842 -286.366458) (xy 59.822842 -285.92272) (xy 62.147958 -285.92272) (xy 62.147958 -286.366458)
			)
		)
	)
	(zone
		(layer "F.Cu")
		(hatch none 0.5)
		(connect_pads
			(clearance 0)
		)
		(min_thickness 0.25)
		(keepout
			(tracks allowed)
			(vias allowed)
			(pads allowed)
			(copperpour allowed)
			(footprints allowed)
		)
		(placement
			(enabled no)
			(sheetname "")
		)
		(fill
			(thermal_gap 0.5)
			(thermal_bridge_width 0.5)
			(island_removal_mode 0)
		)
		(polygon
			(pts
				(xy 413.275526 -282.005024) (xy 413.275526 -281.776424) (xy 415.307526 -281.776424) (xy 415.307526 -282.005024)
			)
		)
	)
	(zone
		(layer "F.Cu")
		(hatch none 0.5)
		(connect_pads
			(clearance 0)
		)
		(min_thickness 0.25)
		(keepout
			(tracks allowed)
			(vias allowed)
			(pads allowed)
			(copperpour allowed)
			(footprints allowed)
		)
		(placement
			(enabled no)
			(sheetname "")
		)
		(fill
			(thermal_gap 0.5)
			(thermal_bridge_width 0.5)
			(island_removal_mode 0)
		)
		(polygon
			(pts
				(xy 424.919394 -264.776204) (xy 426.951394 -264.776204) (xy 426.951394 -265.004804) (xy 424.919394 -265.004804)
				(xy 424.75277 -265.004804) (xy 424.631104 -265.004804) (xy 424.631104 -264.776204) (xy 424.75277 -264.776204)
			)
		)
	)
	(zone
		(layer "F.Cu")
		(hatch none 0.5)
		(connect_pads
			(clearance 0)
		)
		(min_thickness 0.25)
		(keepout
			(tracks allowed)
			(vias allowed)
			(pads allowed)
			(copperpour allowed)
			(footprints allowed)
		)
		(placement
			(enabled no)
			(sheetname "")
		)
		(fill
			(thermal_gap 0.5)
			(thermal_bridge_width 0.5)
			(island_removal_mode 0)
		)
		(polygon
			(pts
				(xy 41.29151 -294.01643) (xy 41.29151 -293.572692) (xy 43.616626 -293.572692) (xy 43.616626 -294.01643)
			)
		)
	)
	(zone
		(layer "F.Cu")
		(hatch none 0.5)
		(connect_pads
			(clearance 0)
		)
		(min_thickness 0.25)
		(keepout
			(tracks allowed)
			(vias allowed)
			(pads allowed)
			(copperpour allowed)
			(footprints allowed)
		)
		(placement
			(enabled no)
			(sheetname "")
		)
		(fill
			(thermal_gap 0.5)
			(thermal_bridge_width 0.5)
			(island_removal_mode 0)
		)
		(polygon
			(pts
				(xy 304.319178 -220.066616) (xy 304.319178 -219.622878) (xy 306.644294 -219.622878) (xy 306.644294 -220.066616)
			)
		)
	)
	(zone
		(layer "F.Cu")
		(hatch none 0.5)
		(connect_pads
			(clearance 0)
		)
		(min_thickness 0.25)
		(keepout
			(tracks not_allowed)
			(vias allowed)
			(pads allowed)
			(copperpour not_allowed)
			(footprints allowed)
		)
		(placement
			(enabled no)
			(sheetname "")
		)
		(fill
			(thermal_gap 0.5)
			(thermal_bridge_width 0.5)
			(island_removal_mode 0)
		)
		(polygon
			(pts
				(arc
					(start 254.124968 -360.764074)
					(mid 258.12496 -356.764082)
					(end 262.124952 -360.764074)
				)
				(arc
					(start 262.124952 -360.764074)
					(mid 258.12496 -364.764066)
					(end 254.124968 -360.764074)
				)
			)
		)
	)
	(zone
		(layer "F.Cu")
		(hatch none 0.5)
		(connect_pads
			(clearance 0)
		)
		(min_thickness 0.25)
		(keepout
			(tracks allowed)
			(vias allowed)
			(pads allowed)
			(copperpour allowed)
			(footprints allowed)
		)
		(placement
			(enabled no)
			(sheetname "")
		)
		(fill
			(thermal_gap 0.5)
			(thermal_bridge_width 0.5)
			(island_removal_mode 0)
		)
		(polygon
			(pts
				(xy 413.275526 -314.304934) (xy 413.275526 -314.076334) (xy 415.307526 -314.076334) (xy 415.307526 -314.304934)
			)
		)
	)
	(zone
		(layer "F.Cu")
		(hatch none 0.5)
		(connect_pads
			(clearance 0)
		)
		(min_thickness 0.25)
		(keepout
			(tracks allowed)
			(vias allowed)
			(pads allowed)
			(copperpour allowed)
			(footprints allowed)
		)
		(placement
			(enabled no)
			(sheetname "")
		)
		(fill
			(thermal_gap 0.5)
			(thermal_bridge_width 0.5)
			(island_removal_mode 0)
		)
		(polygon
			(pts
				(xy 287.90138 -361.96778) (xy 286.08528 -361.96778) (xy 286.08528 -360.58856) (xy 287.90138 -360.58856)
			)
		)
	)
	(zone
		(layer "F.Cu")
		(hatch none 0.5)
		(connect_pads
			(clearance 0)
		)
		(min_thickness 0.25)
		(keepout
			(tracks allowed)
			(vias allowed)
			(pads allowed)
			(copperpour allowed)
			(footprints allowed)
		)
		(placement
			(enabled no)
			(sheetname "")
		)
		(fill
			(thermal_gap 0.5)
			(thermal_bridge_width 0.5)
			(island_removal_mode 0)
		)
		(polygon
			(pts
				(xy 210.598258 -235.2548) (xy 210.598258 -235.0262) (xy 212.630258 -235.0262) (xy 212.630258 -235.2548)
			)
		)
	)
	(zone
		(layer "F.Cu")
		(hatch none 0.5)
		(connect_pads
			(clearance 0)
		)
		(min_thickness 0.25)
		(keepout
			(tracks allowed)
			(vias allowed)
			(pads allowed)
			(copperpour allowed)
			(footprints allowed)
		)
		(placement
			(enabled no)
			(sheetname "")
		)
		(fill
			(thermal_gap 0.5)
			(thermal_bridge_width 0.5)
			(island_removal_mode 0)
		)
		(polygon
			(pts
				(xy 429.17618 -164.582348) (xy 429.17618 -167.079168) (xy 429.65878 -167.561768) (xy 430.06518 -167.561768)
				(xy 430.88306 -166.743888) (xy 430.88306 -160.327848) (xy 430.47412 -159.918908) (xy 429.34636 -161.046668)
				(xy 429.34636 -164.412168)
			)
		)
	)
	(zone
		(layer "F.Cu")
		(hatch none 0.5)
		(connect_pads
			(clearance 0)
		)
		(min_thickness 0.25)
		(keepout
			(tracks allowed)
			(vias allowed)
			(pads allowed)
			(copperpour allowed)
			(footprints allowed)
		)
		(placement
			(enabled no)
			(sheetname "")
		)
		(fill
			(thermal_gap 0.5)
			(thermal_bridge_width 0.5)
			(island_removal_mode 0)
		)
		(polygon
			(pts
				(xy 274.143978 -291.466524) (xy 274.143978 -291.022786) (xy 276.469094 -291.022786) (xy 276.469094 -291.466524)
			)
		)
	)
	(zone
		(layer "F.Cu")
		(hatch none 0.5)
		(connect_pads
			(clearance 0)
		)
		(min_thickness 0.25)
		(keepout
			(tracks allowed)
			(vias allowed)
			(pads allowed)
			(copperpour allowed)
			(footprints allowed)
		)
		(placement
			(enabled no)
			(sheetname "")
		)
		(fill
			(thermal_gap 0.5)
			(thermal_bridge_width 0.5)
			(island_removal_mode 0)
		)
		(polygon
			(pts
				(xy 405.515572 -252.918722) (xy 405.515572 -239.33531) (xy 405.258524 -239.33531) (xy 405.165052 -239.241838)
				(xy 405.165052 -238.787686) (xy 405.257762 -238.694976) (xy 405.515572 -238.694976) (xy 405.515572 -237.080298)
				(xy 405.062182 -237.080298) (xy 404.746968 -236.765084) (xy 404.746968 -235.869988) (xy 404.888446 -235.72851)
				(xy 405.515572 -235.72851) (xy 405.515572 -235.45927) (xy 404.661116 -234.604814) (xy 404.661116 -233.628438)
				(xy 405.515572 -232.773982) (xy 405.515572 -218.348306) (xy 404.91283 -218.348306) (xy 404.776178 -218.211654)
				(xy 404.776178 -218.210638) (xy 404.339044 -218.210638) (xy 403.614382 -217.485976) (xy 403.614382 -216.963752)
				(xy 404.073868 -216.504266) (xy 404.073868 -216.106502) (xy 404.954232 -215.226138) (xy 405.515572 -215.226138)
				(xy 405.515572 -209.42173) (xy 404.902924 -208.809082) (xy 404.902924 -208.042002) (xy 404.902924 -206.597504)
				(xy 404.902924 -206.36992) (xy 404.902924 -204.818996) (xy 404.902924 -204.141324) (xy 405.060404 -203.983844)
				(xy 405.515572 -203.983844) (xy 405.515572 -200.575418) (xy 405.137874 -200.575418) (xy 405.007572 -200.445116)
				(xy 405.007572 -199.17537) (xy 405.515572 -199.17537) (xy 405.515572 -198.419974) (xy 404.972012 -198.419974)
				(xy 404.91283 -198.360792) (xy 404.91283 -198.064628) (xy 404.929848 -198.04761) (xy 404.929848 -197.346316)
				(xy 405.20239 -197.073774) (xy 405.515572 -197.073774) (xy 405.515572 -194.7418) (xy 405.867616 -194.389756)
				(xy 463.269838 -194.389756) (xy 464.044538 -195.164456) (xy 464.044538 -252.7427) (xy 463.410808 -253.37643)
				(xy 405.97328 -253.37643)
			)
		)
	)
	(zone
		(layer "F.Cu")
		(hatch none 0.5)
		(connect_pads
			(clearance 0)
		)
		(min_thickness 0.25)
		(keepout
			(tracks allowed)
			(vias allowed)
			(pads allowed)
			(copperpour allowed)
			(footprints allowed)
		)
		(placement
			(enabled no)
			(sheetname "")
		)
		(fill
			(thermal_gap 0.5)
			(thermal_bridge_width 0.5)
			(island_removal_mode 0)
		)
		(polygon
			(pts
				(xy 443.450726 -217.40495) (xy 443.450726 -217.17635) (xy 445.482726 -217.17635) (xy 445.482726 -217.40495)
			)
		)
	)
	(zone
		(layer "F.Cu")
		(hatch none 0.5)
		(connect_pads
			(clearance 0)
		)
		(min_thickness 0.25)
		(keepout
			(tracks allowed)
			(vias allowed)
			(pads allowed)
			(copperpour allowed)
			(footprints allowed)
		)
		(placement
			(enabled no)
			(sheetname "")
		)
		(fill
			(thermal_gap 0.5)
			(thermal_bridge_width 0.5)
			(island_removal_mode 0)
		)
		(polygon
			(pts
				(xy 443.450726 -300.705012) (xy 443.450726 -300.476412) (xy 445.482726 -300.476412) (xy 445.482726 -300.705012)
			)
		)
	)
	(zone
		(layer "F.Cu")
		(hatch none 0.5)
		(connect_pads
			(clearance 0)
		)
		(min_thickness 0.25)
		(keepout
			(tracks allowed)
			(vias allowed)
			(pads allowed)
			(copperpour allowed)
			(footprints allowed)
		)
		(placement
			(enabled no)
			(sheetname "")
		)
		(fill
			(thermal_gap 0.5)
			(thermal_bridge_width 0.5)
			(island_removal_mode 0)
		)
		(polygon
			(pts
				(xy 413.275526 -240.126266) (xy 415.307526 -240.126266) (xy 415.489136 -240.126266) (xy 415.489136 -240.905284)
				(xy 413.098742 -240.905284) (xy 413.098742 -240.126266)
			)
		)
	)
	(zone
		(layer "F.Cu")
		(hatch none 0.5)
		(connect_pads
			(clearance 0)
		)
		(min_thickness 0.25)
		(keepout
			(tracks allowed)
			(vias allowed)
			(pads allowed)
			(copperpour allowed)
			(footprints allowed)
		)
		(placement
			(enabled no)
			(sheetname "")
		)
		(fill
			(thermal_gap 0.5)
			(thermal_bridge_width 0.5)
			(island_removal_mode 0)
		)
		(polygon
			(pts
				(xy 424.919394 -313.226196) (xy 426.951394 -313.226196) (xy 426.951394 -313.454796) (xy 424.919394 -313.454796)
				(xy 424.788076 -313.454796) (xy 424.762168 -313.454796) (xy 424.762168 -313.226196) (xy 424.788076 -313.226196)
			)
		)
	)
	(zone
		(layer "F.Cu")
		(hatch none 0.5)
		(connect_pads
			(clearance 0)
		)
		(min_thickness 0.25)
		(keepout
			(tracks allowed)
			(vias allowed)
			(pads allowed)
			(copperpour allowed)
			(footprints allowed)
		)
		(placement
			(enabled no)
			(sheetname "")
		)
		(fill
			(thermal_gap 0.5)
			(thermal_bridge_width 0.5)
			(island_removal_mode 0)
		)
		(polygon
			(pts
				(xy 455.094594 -294.526208) (xy 457.126594 -294.526208) (xy 457.126594 -294.754808) (xy 455.094594 -294.754808)
				(xy 454.963276 -294.754808) (xy 454.937368 -294.754808) (xy 454.937368 -294.526208) (xy 454.963276 -294.526208)
			)
		)
	)
	(zone
		(layer "F.Cu")
		(hatch none 0.5)
		(connect_pads
			(clearance 0)
		)
		(min_thickness 0.25)
		(keepout
			(tracks allowed)
			(vias allowed)
			(pads allowed)
			(copperpour allowed)
			(footprints allowed)
		)
		(placement
			(enabled no)
			(sheetname "")
		)
		(fill
			(thermal_gap 0.5)
			(thermal_bridge_width 0.5)
			(island_removal_mode 0)
		)
		(polygon
			(pts
				(xy 59.822842 -314.41644) (xy 59.822842 -313.972702) (xy 62.147958 -313.972702) (xy 62.147958 -314.41644)
			)
		)
	)
	(zone
		(layer "F.Cu")
		(hatch none 0.5)
		(connect_pads
			(clearance 0)
		)
		(min_thickness 0.25)
		(keepout
			(tracks allowed)
			(vias allowed)
			(pads allowed)
			(copperpour allowed)
			(footprints allowed)
		)
		(placement
			(enabled no)
			(sheetname "")
		)
		(fill
			(thermal_gap 0.5)
			(thermal_bridge_width 0.5)
			(island_removal_mode 0)
		)
		(polygon
			(pts
				(xy 176.979326 -264.776204) (xy 179.011326 -264.776204) (xy 179.011326 -265.004804) (xy 176.979326 -265.004804)
				(xy 176.812702 -265.004804) (xy 176.691036 -265.004804) (xy 176.691036 -264.776204) (xy 176.812702 -264.776204)
			)
		)
	)
	(zone
		(layer "F.Cu")
		(hatch none 0.5)
		(connect_pads
			(clearance 0)
		)
		(min_thickness 0.25)
		(keepout
			(tracks allowed)
			(vias allowed)
			(pads allowed)
			(copperpour allowed)
			(footprints allowed)
		)
		(placement
			(enabled no)
			(sheetname "")
		)
		(fill
			(thermal_gap 0.5)
			(thermal_bridge_width 0.5)
			(island_removal_mode 0)
		)
		(polygon
			(pts
				(xy 180.423058 -291.355018) (xy 180.423058 -291.126418) (xy 182.455058 -291.126418) (xy 182.455058 -291.355018)
			)
		)
	)
	(zone
		(layer "F.Cu")
		(hatch none 0.5)
		(connect_pads
			(clearance 0)
		)
		(min_thickness 0.25)
		(keepout
			(tracks allowed)
			(vias allowed)
			(pads allowed)
			(copperpour allowed)
			(footprints allowed)
		)
		(placement
			(enabled no)
			(sheetname "")
		)
		(fill
			(thermal_gap 0.5)
			(thermal_bridge_width 0.5)
			(island_removal_mode 0)
		)
		(polygon
			(pts
				(xy 207.154526 -284.556962) (xy 209.186526 -284.556962) (xy 209.186526 -284.328362) (xy 207.154526 -284.328362)
				(xy 207.023208 -284.328362) (xy 206.9973 -284.328362) (xy 206.9973 -284.556962) (xy 207.023208 -284.556962)
			)
		)
	)
	(zone
		(layer "F.Cu")
		(hatch none 0.5)
		(connect_pads
			(clearance 0)
		)
		(min_thickness 0.25)
		(keepout
			(tracks allowed)
			(vias allowed)
			(pads allowed)
			(copperpour allowed)
			(footprints allowed)
		)
		(placement
			(enabled no)
			(sheetname "")
		)
		(fill
			(thermal_gap 0.5)
			(thermal_bridge_width 0.5)
			(island_removal_mode 0)
		)
		(polygon
			(pts
				(xy 87.50046 -217.716608) (xy 87.78748 -217.716608) (xy 87.81796 -217.686128) (xy 87.81796 -217.058748)
				(xy 87.7316 -216.972388) (xy 87.54364 -216.972388) (xy 87.46998 -217.046048) (xy 87.46998 -217.686128)
			)
		)
	)
	(zone
		(layer "F.Cu")
		(hatch none 0.5)
		(connect_pads
			(clearance 0)
		)
		(min_thickness 0.25)
		(keepout
			(tracks allowed)
			(vias allowed)
			(pads allowed)
			(copperpour allowed)
			(footprints allowed)
		)
		(placement
			(enabled no)
			(sheetname "")
		)
		(fill
			(thermal_gap 0.5)
			(thermal_bridge_width 0.5)
			(island_removal_mode 0)
		)
		(polygon
			(pts
				(xy 376.694954 -336.318606) (xy 374.878854 -336.318606) (xy 374.878854 -334.939386) (xy 376.694954 -334.939386)
			)
		)
	)
	(zone
		(layer "F.Cu")
		(hatch none 0.5)
		(connect_pads
			(clearance 0)
		)
		(min_thickness 0.25)
		(keepout
			(tracks allowed)
			(vias allowed)
			(pads allowed)
			(copperpour allowed)
			(footprints allowed)
		)
		(placement
			(enabled no)
			(sheetname "")
		)
		(fill
			(thermal_gap 0.5)
			(thermal_bridge_width 0.5)
			(island_removal_mode 0)
		)
		(polygon
			(pts
				(xy 14.560042 -198.816468) (xy 14.560042 -198.37273) (xy 16.885158 -198.37273) (xy 16.885158 -198.816468)
			)
		)
	)
	(zone
		(layer "F.Cu")
		(hatch none 0.5)
		(connect_pads
			(clearance 0)
		)
		(min_thickness 0.25)
		(keepout
			(tracks allowed)
			(vias allowed)
			(pads allowed)
			(copperpour allowed)
			(footprints allowed)
		)
		(placement
			(enabled no)
			(sheetname "")
		)
		(fill
			(thermal_gap 0.5)
			(thermal_bridge_width 0.5)
			(island_removal_mode 0)
		)
		(polygon
			(pts
				(xy 76.8096 -347.967808) (xy 76.8096 -345.491308) (xy 82.46618 -345.491308) (xy 82.46618 -347.967808)
			)
		)
	)
	(zone
		(layer "F.Cu")
		(hatch none 0.5)
		(connect_pads
			(clearance 0)
		)
		(min_thickness 0.25)
		(keepout
			(tracks allowed)
			(vias allowed)
			(pads allowed)
			(copperpour allowed)
			(footprints not_allowed)
		)
		(placement
			(enabled no)
			(sheetname "")
		)
		(fill
			(thermal_gap 0.5)
			(thermal_bridge_width 0.5)
			(island_removal_mode 0)
		)
		(polygon
			(pts
				(xy 435.92877 -330.091796) (xy 442.02858 -330.091796) (xy 442.02858 -186.09183) (xy 435.92877 -186.09183)
			)
		)
	)
	(zone
		(layer "F.Cu")
		(hatch none 0.5)
		(connect_pads
			(clearance 0)
		)
		(min_thickness 0.25)
		(keepout
			(tracks allowed)
			(vias allowed)
			(pads allowed)
			(copperpour allowed)
			(footprints allowed)
		)
		(placement
			(enabled no)
			(sheetname "")
		)
		(fill
			(thermal_gap 0.5)
			(thermal_bridge_width 0.5)
			(island_removal_mode 0)
		)
		(polygon
			(pts
				(xy 165.335458 -203.805028) (xy 165.335458 -203.576428) (xy 167.367458 -203.576428) (xy 167.367458 -203.805028)
			)
		)
	)
	(zone
		(layer "F.Cu")
		(hatch none 0.5)
		(connect_pads
			(clearance 0)
		)
		(min_thickness 0.25)
		(keepout
			(tracks allowed)
			(vias allowed)
			(pads allowed)
			(copperpour allowed)
			(footprints allowed)
		)
		(placement
			(enabled no)
			(sheetname "")
		)
		(fill
			(thermal_gap 0.5)
			(thermal_bridge_width 0.5)
			(island_removal_mode 0)
		)
		(polygon
			(pts
				(xy 165.335458 -264.15492) (xy 165.335458 -263.92632) (xy 167.367458 -263.92632) (xy 167.367458 -264.15492)
			)
		)
	)
	(zone
		(layer "F.Cu")
		(hatch none 0.5)
		(connect_pads
			(clearance 0)
		)
		(min_thickness 0.25)
		(keepout
			(tracks allowed)
			(vias allowed)
			(pads allowed)
			(copperpour allowed)
			(footprints allowed)
		)
		(placement
			(enabled no)
			(sheetname "")
		)
		(fill
			(thermal_gap 0.5)
			(thermal_bridge_width 0.5)
			(island_removal_mode 0)
		)
		(polygon
			(pts
				(xy 458.538326 -199.554846) (xy 458.538326 -199.326246) (xy 460.570326 -199.326246) (xy 460.570326 -199.554846)
			)
		)
	)
	(zone
		(layer "F.Cu")
		(hatch none 0.5)
		(connect_pads
			(clearance 0)
		)
		(min_thickness 0.25)
		(keepout
			(tracks allowed)
			(vias allowed)
			(pads allowed)
			(copperpour allowed)
			(footprints allowed)
		)
		(placement
			(enabled no)
			(sheetname "")
		)
		(fill
			(thermal_gap 0.5)
			(thermal_bridge_width 0.5)
			(island_removal_mode 0)
		)
		(polygon
			(pts
				(xy 154.68854 -48.49876) (xy 154.68854 -47.59706) (xy 157.89148 -47.59706) (xy 157.89148 -48.49876)
			)
		)
	)
	(zone
		(layer "F.Cu")
		(hatch none 0.5)
		(connect_pads
			(clearance 0)
		)
		(min_thickness 0.25)
		(keepout
			(tracks allowed)
			(vias allowed)
			(pads allowed)
			(copperpour allowed)
			(footprints allowed)
		)
		(placement
			(enabled no)
			(sheetname "")
		)
		(fill
			(thermal_gap 0.5)
			(thermal_bridge_width 0.5)
			(island_removal_mode 0)
		)
		(polygon
			(pts
				(xy 289.231578 -205.616556) (xy 289.231578 -205.172818) (xy 291.556694 -205.172818) (xy 291.556694 -205.616556)
			)
		)
	)
	(zone
		(layer "F.Cu")
		(hatch none 0.5)
		(connect_pads
			(clearance 0)
		)
		(min_thickness 0.25)
		(keepout
			(tracks allowed)
			(vias allowed)
			(pads allowed)
			(copperpour allowed)
			(footprints allowed)
		)
		(placement
			(enabled no)
			(sheetname "")
		)
		(fill
			(thermal_gap 0.5)
			(thermal_bridge_width 0.5)
			(island_removal_mode 0)
		)
		(polygon
			(pts
				(xy 386.207 -219.243148) (xy 386.49402 -219.243148) (xy 386.5245 -219.212668) (xy 386.5245 -218.585288)
				(xy 386.43814 -218.498928) (xy 386.25018 -218.498928) (xy 386.17652 -218.572588) (xy 386.17652 -219.212668)
			)
		)
	)
	(zone
		(layer "F.Cu")
		(hatch none 0.5)
		(connect_pads
			(clearance 0)
		)
		(min_thickness 0.25)
		(keepout
			(tracks allowed)
			(vias allowed)
			(pads allowed)
			(copperpour allowed)
			(footprints allowed)
		)
		(placement
			(enabled no)
			(sheetname "")
		)
		(fill
			(thermal_gap 0.5)
			(thermal_bridge_width 0.5)
			(island_removal_mode 0)
		)
		(polygon
			(pts
				(xy 18.18894 -397.6624) (xy 18.18894 -395.19606) (xy 20.37334 -395.19606) (xy 20.37334 -397.6624)
			)
		)
	)
	(zone
		(layer "F.Cu")
		(hatch none 0.5)
		(connect_pads
			(clearance 0)
		)
		(min_thickness 0.25)
		(keepout
			(tracks allowed)
			(vias allowed)
			(pads allowed)
			(copperpour allowed)
			(footprints allowed)
		)
		(placement
			(enabled no)
			(sheetname "")
		)
		(fill
			(thermal_gap 0.5)
			(thermal_bridge_width 0.5)
			(island_removal_mode 0)
		)
		(polygon
			(pts
				(xy 104.32288 -400.268948) (xy 104.32288 -398.490948) (xy 107.37088 -398.490948) (xy 107.37088 -400.268948)
			)
		)
	)
	(zone
		(layer "F.Cu")
		(hatch none 0.5)
		(connect_pads
			(clearance 0)
		)
		(min_thickness 0.25)
		(keepout
			(tracks allowed)
			(vias allowed)
			(pads allowed)
			(copperpour allowed)
			(footprints allowed)
		)
		(placement
			(enabled no)
			(sheetname "")
		)
		(fill
			(thermal_gap 0.5)
			(thermal_bridge_width 0.5)
			(island_removal_mode 0)
		)
		(polygon
			(pts
				(xy 289.231578 -294.866568) (xy 289.231578 -294.42283) (xy 291.556694 -294.42283) (xy 291.556694 -294.866568)
			)
		)
	)
	(zone
		(layer "F.Cu")
		(hatch none 0.5)
		(connect_pads
			(clearance 0)
		)
		(min_thickness 0.25)
		(keepout
			(tracks allowed)
			(vias allowed)
			(pads allowed)
			(copperpour allowed)
			(footprints allowed)
		)
		(placement
			(enabled no)
			(sheetname "")
		)
		(fill
			(thermal_gap 0.5)
			(thermal_bridge_width 0.5)
			(island_removal_mode 0)
		)
		(polygon
			(pts
				(xy 424.919394 -203.576428) (xy 426.951394 -203.576428) (xy 426.951394 -203.805028) (xy 424.919394 -203.805028)
				(xy 424.78325 -203.805028) (xy 424.73626 -203.805028) (xy 424.73626 -203.576428) (xy 424.78325 -203.576428)
			)
		)
	)
	(zone
		(layer "F.Cu")
		(hatch none 0.5)
		(connect_pads
			(clearance 0)
		)
		(min_thickness 0.25)
		(keepout
			(tracks allowed)
			(vias allowed)
			(pads allowed)
			(copperpour allowed)
			(footprints allowed)
		)
		(placement
			(enabled no)
			(sheetname "")
		)
		(fill
			(thermal_gap 0.5)
			(thermal_bridge_width 0.5)
			(island_removal_mode 0)
		)
		(polygon
			(pts
				(xy 413.275526 -196.154802) (xy 413.275526 -195.926202) (xy 415.307526 -195.926202) (xy 415.307526 -196.154802)
			)
		)
	)
	(zone
		(layer "F.Cu")
		(hatch none 0.5)
		(connect_pads
			(clearance 0)
		)
		(min_thickness 0.25)
		(keepout
			(tracks allowed)
			(vias allowed)
			(pads allowed)
			(copperpour allowed)
			(footprints allowed)
		)
		(placement
			(enabled no)
			(sheetname "")
		)
		(fill
			(thermal_gap 0.5)
			(thermal_bridge_width 0.5)
			(island_removal_mode 0)
		)
		(polygon
			(pts
				(xy 26.30932 -168.300908) (xy 26.30932 -167.178228) (xy 26.50236 -166.985188) (xy 26.89352 -166.985188)
				(xy 27.33294 -167.424608) (xy 27.33294 -167.965628) (xy 26.99766 -168.300908)
			)
		)
	)
	(zone
		(layer "F.Cu")
		(hatch none 0.5)
		(connect_pads
			(clearance 0)
		)
		(min_thickness 0.25)
		(keepout
			(tracks allowed)
			(vias allowed)
			(pads allowed)
			(copperpour allowed)
			(footprints allowed)
		)
		(placement
			(enabled no)
			(sheetname "")
		)
		(fill
			(thermal_gap 0.5)
			(thermal_bridge_width 0.5)
			(island_removal_mode 0)
		)
		(polygon
			(pts
				(xy 428.363126 -227.604828) (xy 428.363126 -227.376228) (xy 430.395126 -227.376228) (xy 430.395126 -227.604828)
			)
		)
	)
	(zone
		(layer "F.Cu")
		(hatch none 0.5)
		(connect_pads
			(clearance 0)
		)
		(min_thickness 0.25)
		(keepout
			(tracks allowed)
			(vias allowed)
			(pads allowed)
			(copperpour allowed)
			(footprints allowed)
		)
		(placement
			(enabled no)
			(sheetname "")
		)
		(fill
			(thermal_gap 0.5)
			(thermal_bridge_width 0.5)
			(island_removal_mode 0)
		)
		(polygon
			(pts
				(xy 373.54256 -342.590628) (xy 373.54256 -337.952588) (xy 373.54256 -337.792568) (xy 373.66448 -337.670648)
				(xy 374.07088 -337.670648) (xy 374.35282 -337.952588) (xy 379.57252 -337.952588) (xy 379.57252 -342.590628)
			)
		)
	)
	(zone
		(layer "F.Cu")
		(hatch none 0.5)
		(connect_pads
			(clearance 0)
		)
		(min_thickness 0.25)
		(keepout
			(tracks allowed)
			(vias allowed)
			(pads allowed)
			(copperpour allowed)
			(footprints allowed)
		)
		(placement
			(enabled no)
			(sheetname "")
		)
		(fill
			(thermal_gap 0.5)
			(thermal_bridge_width 0.5)
			(island_removal_mode 0)
		)
		(polygon
			(pts
				(xy 307.76291 -293.166546) (xy 307.76291 -292.722808) (xy 310.088026 -292.722808) (xy 310.088026 -293.166546)
			)
		)
	)
	(zone
		(layer "F.Cu")
		(hatch none 0.5)
		(connect_pads
			(clearance 0)
		)
		(min_thickness 0.25)
		(keepout
			(tracks allowed)
			(vias allowed)
			(pads allowed)
			(copperpour allowed)
			(footprints allowed)
		)
		(placement
			(enabled no)
			(sheetname "")
		)
		(fill
			(thermal_gap 0.5)
			(thermal_bridge_width 0.5)
			(island_removal_mode 0)
		)
		(polygon
			(pts
				(xy 210.598258 -241.205004) (xy 210.598258 -240.976404) (xy 212.630258 -240.976404) (xy 212.630258 -241.205004)
			)
		)
	)
	(zone
		(layer "F.Cu")
		(hatch none 0.5)
		(connect_pads
			(clearance 0)
		)
		(min_thickness 0.25)
		(keepout
			(tracks allowed)
			(vias allowed)
			(pads allowed)
			(copperpour allowed)
			(footprints allowed)
		)
		(placement
			(enabled no)
			(sheetname "")
		)
		(fill
			(thermal_gap 0.5)
			(thermal_bridge_width 0.5)
			(island_removal_mode 0)
		)
		(polygon
			(pts
				(xy 192.066926 -223.976438) (xy 194.098926 -223.976438) (xy 194.098926 -224.205038) (xy 192.066926 -224.205038)
				(xy 191.930782 -224.205038) (xy 191.883792 -224.205038) (xy 191.883792 -223.976438) (xy 191.930782 -223.976438)
			)
		)
	)
	(zone
		(layer "F.Cu")
		(hatch none 0.5)
		(connect_pads
			(clearance 0)
		)
		(min_thickness 0.25)
		(keepout
			(tracks allowed)
			(vias allowed)
			(pads allowed)
			(copperpour allowed)
			(footprints allowed)
		)
		(placement
			(enabled no)
			(sheetname "")
		)
		(fill
			(thermal_gap 0.5)
			(thermal_bridge_width 0.5)
			(island_removal_mode 0)
		)
		(polygon
			(pts
				(xy 292.67531 -214.96655) (xy 292.67531 -214.522812) (xy 295.000426 -214.522812) (xy 295.000426 -214.96655)
			)
		)
	)
	(zone
		(layer "F.Cu")
		(hatch none 0.5)
		(connect_pads
			(clearance 0)
		)
		(min_thickness 0.25)
		(keepout
			(tracks allowed)
			(vias allowed)
			(pads allowed)
			(copperpour allowed)
			(footprints allowed)
		)
		(placement
			(enabled no)
			(sheetname "")
		)
		(fill
			(thermal_gap 0.5)
			(thermal_bridge_width 0.5)
			(island_removal_mode 0)
		)
		(polygon
			(pts
				(xy 304.319178 -260.866636) (xy 304.319178 -260.422898) (xy 306.644294 -260.422898) (xy 306.644294 -260.866636)
			)
		)
	)
	(zone
		(layer "F.Cu")
		(hatch none 0.5)
		(connect_pads
			(clearance 0)
		)
		(min_thickness 0.25)
		(keepout
			(tracks allowed)
			(vias allowed)
			(pads allowed)
			(copperpour allowed)
			(footprints allowed)
		)
		(placement
			(enabled no)
			(sheetname "")
		)
		(fill
			(thermal_gap 0.5)
			(thermal_bridge_width 0.5)
			(island_removal_mode 0)
		)
		(polygon
			(pts
				(xy 428.363126 -287.954974) (xy 428.363126 -287.726374) (xy 430.395126 -287.726374) (xy 430.395126 -287.954974)
			)
		)
	)
	(zone
		(layer "F.Cu")
		(hatch none 0.5)
		(connect_pads
			(clearance 0)
		)
		(min_thickness 0.25)
		(keepout
			(tracks allowed)
			(vias allowed)
			(pads allowed)
			(copperpour allowed)
			(footprints allowed)
		)
		(placement
			(enabled no)
			(sheetname "")
		)
		(fill
			(thermal_gap 0.5)
			(thermal_bridge_width 0.5)
			(island_removal_mode 0)
		)
		(polygon
			(pts
				(xy 274.143978 -270.622776) (xy 276.469094 -270.622776) (xy 276.543262 -270.622776) (xy 276.543262 -271.53489)
				(xy 274.022566 -271.53489) (xy 274.022566 -270.622776)
			)
		)
	)
	(zone
		(layer "F.Cu")
		(hatch none 0.5)
		(connect_pads
			(clearance 0)
		)
		(min_thickness 0.25)
		(keepout
			(tracks allowed)
			(vias allowed)
			(pads allowed)
			(copperpour allowed)
			(footprints allowed)
		)
		(placement
			(enabled no)
			(sheetname "")
		)
		(fill
			(thermal_gap 0.5)
			(thermal_bridge_width 0.5)
			(island_removal_mode 0)
		)
		(polygon
			(pts
				(xy 180.0098 -54.569868) (xy 180.0098 -52.563268) (xy 183.04002 -52.563268) (xy 183.04002 -54.569868)
			)
		)
	)
	(zone
		(layer "F.Cu")
		(hatch none 0.5)
		(connect_pads
			(clearance 0)
		)
		(min_thickness 0.25)
		(keepout
			(tracks allowed)
			(vias allowed)
			(pads allowed)
			(copperpour allowed)
			(footprints allowed)
		)
		(placement
			(enabled no)
			(sheetname "")
		)
		(fill
			(thermal_gap 0.5)
			(thermal_bridge_width 0.5)
			(island_removal_mode 0)
		)
		(polygon
			(pts
				(xy 52.65674 -147.833588) (xy 52.65674 -146.086068) (xy 54.59222 -146.086068) (xy 54.59222 -147.833588)
			)
		)
	)
	(zone
		(layer "F.Cu")
		(hatch none 0.5)
		(connect_pads
			(clearance 0)
		)
		(min_thickness 0.25)
		(keepout
			(tracks allowed)
			(vias allowed)
			(pads allowed)
			(copperpour allowed)
			(footprints allowed)
		)
		(placement
			(enabled no)
			(sheetname "")
		)
		(fill
			(thermal_gap 0.5)
			(thermal_bridge_width 0.5)
			(island_removal_mode 0)
		)
		(polygon
			(pts
				(xy 26.20391 -305.066446) (xy 26.20391 -304.622708) (xy 28.529026 -304.622708) (xy 28.529026 -305.066446)
			)
		)
	)
	(zone
		(layer "F.Cu")
		(hatch none 0.5)
		(connect_pads
			(clearance 0)
		)
		(min_thickness 0.25)
		(keepout
			(tracks allowed)
			(vias allowed)
			(pads allowed)
			(copperpour allowed)
			(footprints allowed)
		)
		(placement
			(enabled no)
			(sheetname "")
		)
		(fill
			(thermal_gap 0.5)
			(thermal_bridge_width 0.5)
			(island_removal_mode 0)
		)
		(polygon
			(pts
				(xy 83.315048 -342.787478) (xy 79.779368 -342.787478) (xy 79.779368 -340.704678) (xy 83.315048 -340.704678)
			)
		)
	)
	(zone
		(layer "F.Cu")
		(hatch none 0.5)
		(connect_pads
			(clearance 0)
		)
		(min_thickness 0.25)
		(keepout
			(tracks allowed)
			(vias allowed)
			(pads allowed)
			(copperpour allowed)
			(footprints allowed)
		)
		(placement
			(enabled no)
			(sheetname "")
		)
		(fill
			(thermal_gap 0.5)
			(thermal_bridge_width 0.5)
			(island_removal_mode 0)
		)
		(polygon
			(pts
				(xy 277.58771 -287.216596) (xy 277.58771 -286.772858) (xy 279.912826 -286.772858) (xy 279.912826 -287.216596)
			)
		)
	)
	(zone
		(layer "F.Cu")
		(hatch none 0.5)
		(connect_pads
			(clearance 0)
		)
		(min_thickness 0.25)
		(keepout
			(tracks allowed)
			(vias allowed)
			(pads allowed)
			(copperpour allowed)
			(footprints allowed)
		)
		(placement
			(enabled no)
			(sheetname "")
		)
		(fill
			(thermal_gap 0.5)
			(thermal_bridge_width 0.5)
			(island_removal_mode 0)
		)
		(polygon
			(pts
				(xy 307.76291 -209.0166) (xy 307.76291 -208.572862) (xy 310.088026 -208.572862) (xy 310.088026 -209.0166)
			)
		)
	)
	(zone
		(layer "F.Cu")
		(hatch none 0.5)
		(connect_pads
			(clearance 0)
		)
		(min_thickness 0.25)
		(keepout
			(tracks allowed)
			(vias allowed)
			(pads allowed)
			(copperpour allowed)
			(footprints allowed)
		)
		(placement
			(enabled no)
			(sheetname "")
		)
		(fill
			(thermal_gap 0.5)
			(thermal_bridge_width 0.5)
			(island_removal_mode 0)
		)
		(polygon
			(pts
				(xy 289.231578 -267.66647) (xy 289.231578 -267.222732) (xy 291.556694 -267.222732) (xy 291.556694 -267.66647)
			)
		)
	)
	(zone
		(layer "F.Cu")
		(hatch none 0.5)
		(connect_pads
			(clearance 0)
		)
		(min_thickness 0.25)
		(keepout
			(tracks allowed)
			(vias allowed)
			(pads allowed)
			(copperpour allowed)
			(footprints allowed)
		)
		(placement
			(enabled no)
			(sheetname "")
		)
		(fill
			(thermal_gap 0.5)
			(thermal_bridge_width 0.5)
			(island_removal_mode 0)
		)
		(polygon
			(pts
				(xy 41.29151 -314.41644) (xy 41.29151 -313.972702) (xy 43.616626 -313.972702) (xy 43.616626 -314.41644)
			)
		)
	)
	(zone
		(layer "F.Cu")
		(hatch none 0.5)
		(connect_pads
			(clearance 0)
		)
		(min_thickness 0.25)
		(keepout
			(tracks allowed)
			(vias allowed)
			(pads allowed)
			(copperpour allowed)
			(footprints allowed)
		)
		(placement
			(enabled no)
			(sheetname "")
		)
		(fill
			(thermal_gap 0.5)
			(thermal_bridge_width 0.5)
			(island_removal_mode 0)
		)
		(polygon
			(pts
				(xy 424.919394 -195.926456) (xy 426.951394 -195.926456) (xy 426.951394 -196.155056) (xy 424.919394 -196.155056)
				(xy 424.78325 -196.155056) (xy 424.73626 -196.155056) (xy 424.73626 -195.926456) (xy 424.78325 -195.926456)
			)
		)
	)
	(zone
		(layer "F.Cu")
		(hatch none 0.5)
		(connect_pads
			(clearance 0)
		)
		(min_thickness 0.25)
		(keepout
			(tracks allowed)
			(vias allowed)
			(pads allowed)
			(copperpour allowed)
			(footprints allowed)
		)
		(placement
			(enabled no)
			(sheetname "")
		)
		(fill
			(thermal_gap 0.5)
			(thermal_bridge_width 0.5)
			(island_removal_mode 0)
		)
		(polygon
			(pts
				(xy 135.08736 -288.219388) (xy 135.37438 -288.219388) (xy 135.40486 -288.188908) (xy 135.40486 -287.561528)
				(xy 135.3185 -287.475168) (xy 135.13054 -287.475168) (xy 135.05688 -287.548828) (xy 135.05688 -288.188908)
			)
		)
	)
	(zone
		(layer "F.Cu")
		(hatch none 0.5)
		(connect_pads
			(clearance 0)
		)
		(min_thickness 0.25)
		(keepout
			(tracks allowed)
			(vias allowed)
			(pads allowed)
			(copperpour allowed)
			(footprints allowed)
		)
		(placement
			(enabled no)
			(sheetname "")
		)
		(fill
			(thermal_gap 0.5)
			(thermal_bridge_width 0.5)
			(island_removal_mode 0)
		)
		(polygon
			(pts
				(xy 428.363126 -276.904958) (xy 428.363126 -276.676358) (xy 430.395126 -276.676358) (xy 430.395126 -276.904958)
			)
		)
	)
	(zone
		(layer "F.Cu")
		(hatch none 0.5)
		(connect_pads
			(clearance 0)
		)
		(min_thickness 0.25)
		(keepout
			(tracks allowed)
			(vias allowed)
			(pads allowed)
			(copperpour allowed)
			(footprints allowed)
		)
		(placement
			(enabled no)
			(sheetname "")
		)
		(fill
			(thermal_gap 0.5)
			(thermal_bridge_width 0.5)
			(island_removal_mode 0)
		)
		(polygon
			(pts
				(xy 424.919394 -309.826406) (xy 426.951394 -309.826406) (xy 426.951394 -310.055006) (xy 424.919394 -310.055006)
				(xy 424.78325 -310.055006) (xy 424.73626 -310.055006) (xy 424.73626 -309.826406) (xy 424.78325 -309.826406)
			)
		)
	)
	(zone
		(layer "F.Cu")
		(hatch none 0.5)
		(connect_pads
			(clearance 0)
		)
		(min_thickness 0.25)
		(keepout
			(tracks not_allowed)
			(vias allowed)
			(pads allowed)
			(copperpour not_allowed)
			(footprints allowed)
		)
		(placement
			(enabled no)
			(sheetname "")
		)
		(fill
			(thermal_gap 0.5)
			(thermal_bridge_width 0.5)
			(island_removal_mode 0)
		)
		(polygon
			(pts
				(arc
					(start 340.474808 -297.515026)
					(mid 338.379816 -299.610018)
					(end 336.284824 -297.515026)
				)
				(arc
					(start 336.284824 -297.515026)
					(mid 338.379816 -295.420034)
					(end 340.474808 -297.515026)
				)
			)
		)
	)
	(zone
		(layer "F.Cu")
		(hatch none 0.5)
		(connect_pads
			(clearance 0)
		)
		(min_thickness 0.25)
		(keepout
			(tracks allowed)
			(vias allowed)
			(pads allowed)
			(copperpour allowed)
			(footprints allowed)
		)
		(placement
			(enabled no)
			(sheetname "")
		)
		(fill
			(thermal_gap 0.5)
			(thermal_bridge_width 0.5)
			(island_removal_mode 0)
		)
		(polygon
			(pts
				(xy 207.154526 -210.376262) (xy 209.186526 -210.376262) (xy 209.186526 -210.604862) (xy 207.154526 -210.604862)
				(xy 207.023208 -210.604862) (xy 206.9973 -210.604862) (xy 206.9973 -210.376262) (xy 207.023208 -210.376262)
			)
		)
	)
	(zone
		(layer "F.Cu")
		(hatch none 0.5)
		(connect_pads
			(clearance 0)
		)
		(min_thickness 0.25)
		(keepout
			(tracks allowed)
			(vias allowed)
			(pads allowed)
			(copperpour allowed)
			(footprints allowed)
		)
		(placement
			(enabled no)
			(sheetname "")
		)
		(fill
			(thermal_gap 0.5)
			(thermal_bridge_width 0.5)
			(island_removal_mode 0)
		)
		(polygon
			(pts
				(xy 195.510658 -235.876338) (xy 197.542658 -235.876338) (xy 197.542658 -235.878624) (xy 197.721474 -235.878624)
				(xy 197.721474 -236.11586) (xy 197.902576 -236.296962) (xy 197.91807 -236.312456) (xy 197.91807 -236.501432)
				(xy 197.902576 -236.516926) (xy 197.791578 -236.627924) (xy 197.750938 -236.668564) (xy 195.289678 -236.668564)
				(xy 195.148454 -236.52734) (xy 195.148454 -236.330236) (xy 195.229988 -236.248702) (xy 195.288916 -236.189774)
				(xy 195.288916 -235.876338) (xy 195.327524 -235.876338) (xy 195.374514 -235.876338)
			)
		)
	)
	(zone
		(layer "F.Cu")
		(hatch none 0.5)
		(connect_pads
			(clearance 0)
		)
		(min_thickness 0.25)
		(keepout
			(tracks allowed)
			(vias allowed)
			(pads allowed)
			(copperpour allowed)
			(footprints allowed)
		)
		(placement
			(enabled no)
			(sheetname "")
		)
		(fill
			(thermal_gap 0.5)
			(thermal_bridge_width 0.5)
			(island_removal_mode 0)
		)
		(polygon
			(pts
				(xy 11.11631 -245.566438) (xy 11.11631 -245.1227) (xy 13.441426 -245.1227) (xy 13.441426 -245.566438)
			)
		)
	)
	(zone
		(layer "F.Cu")
		(hatch none 0.5)
		(connect_pads
			(clearance 0)
		)
		(min_thickness 0.25)
		(keepout
			(tracks allowed)
			(vias allowed)
			(pads allowed)
			(copperpour allowed)
			(footprints allowed)
		)
		(placement
			(enabled no)
			(sheetname "")
		)
		(fill
			(thermal_gap 0.5)
			(thermal_bridge_width 0.5)
			(island_removal_mode 0)
		)
		(polygon
			(pts
				(xy 409.831794 -233.326432) (xy 411.863794 -233.326432) (xy 412.026862 -233.326432) (xy 412.026862 -234.0737)
				(xy 409.660344 -234.0737) (xy 409.660344 -233.326432)
			)
		)
	)
	(zone
		(layer "F.Cu")
		(hatch none 0.5)
		(connect_pads
			(clearance 0)
		)
		(min_thickness 0.25)
		(keepout
			(tracks allowed)
			(vias allowed)
			(pads allowed)
			(copperpour allowed)
			(footprints allowed)
		)
		(placement
			(enabled no)
			(sheetname "")
		)
		(fill
			(thermal_gap 0.5)
			(thermal_bridge_width 0.5)
			(island_removal_mode 0)
		)
		(polygon
			(pts
				(xy 405.731726 -271.576546) (xy 407.763726 -271.576546) (xy 407.763726 -271.578832) (xy 407.942542 -271.578832)
				(xy 408.123644 -271.578832) (xy 408.151076 -271.578832) (xy 408.151076 -272.368772) (xy 408.051 -272.368772)
				(xy 405.510746 -272.368772) (xy 405.32685 -272.368772) (xy 405.32685 -271.576546) (xy 405.369522 -271.576546)
				(xy 405.451056 -271.576546) (xy 405.548592 -271.576546) (xy 405.595582 -271.576546)
			)
		)
	)
	(zone
		(layer "F.Cu")
		(hatch none 0.5)
		(connect_pads
			(clearance 0)
		)
		(min_thickness 0.25)
		(keepout
			(tracks allowed)
			(vias allowed)
			(pads allowed)
			(copperpour allowed)
			(footprints allowed)
		)
		(placement
			(enabled no)
			(sheetname "")
		)
		(fill
			(thermal_gap 0.5)
			(thermal_bridge_width 0.5)
			(island_removal_mode 0)
		)
		(polygon
			(pts
				(xy 424.919394 -201.876406) (xy 426.951394 -201.876406) (xy 426.951394 -202.105006) (xy 424.919394 -202.105006)
				(xy 424.78325 -202.105006) (xy 424.73626 -202.105006) (xy 424.73626 -201.876406) (xy 424.78325 -201.876406)
			)
		)
	)
	(zone
		(layer "F.Cu")
		(hatch none 0.5)
		(connect_pads
			(clearance 0)
		)
		(min_thickness 0.25)
		(keepout
			(tracks allowed)
			(vias allowed)
			(pads allowed)
			(copperpour allowed)
			(footprints allowed)
		)
		(placement
			(enabled no)
			(sheetname "")
		)
		(fill
			(thermal_gap 0.5)
			(thermal_bridge_width 0.5)
			(island_removal_mode 0)
		)
		(polygon
			(pts
				(xy 304.319432 -201.366374) (xy 304.319432 -200.922636) (xy 306.644548 -200.922636) (xy 306.644548 -201.366374)
			)
		)
	)
	(zone
		(layer "F.Cu")
		(hatch none 0.5)
		(connect_pads
			(clearance 0)
		)
		(min_thickness 0.25)
		(keepout
			(tracks allowed)
			(vias allowed)
			(pads allowed)
			(copperpour allowed)
			(footprints allowed)
		)
		(placement
			(enabled no)
			(sheetname "")
		)
		(fill
			(thermal_gap 0.5)
			(thermal_bridge_width 0.5)
			(island_removal_mode 0)
		)
		(polygon
			(pts
				(xy 409.831794 -272.42643) (xy 411.863794 -272.42643) (xy 411.863794 -272.428716) (xy 412.04261 -272.428716)
				(xy 412.223712 -272.428716) (xy 412.251144 -272.428716) (xy 412.251144 -273.218656) (xy 412.151068 -273.218656)
				(xy 409.610814 -273.218656) (xy 409.426918 -273.218656) (xy 409.426918 -272.42643) (xy 409.46959 -272.42643)
				(xy 409.551124 -272.42643) (xy 409.64866 -272.42643) (xy 409.69565 -272.42643)
			)
		)
	)
	(zone
		(layer "F.Cu")
		(hatch none 0.5)
		(connect_pads
			(clearance 0)
		)
		(min_thickness 0.25)
		(keepout
			(tracks not_allowed)
			(vias allowed)
			(pads allowed)
			(copperpour not_allowed)
			(footprints allowed)
		)
		(placement
			(enabled no)
			(sheetname "")
		)
		(fill
			(thermal_gap 0.5)
			(thermal_bridge_width 0.5)
			(island_removal_mode 0)
		)
		(polygon
			(pts
				(arc
					(start 327.95464 -251.76988)
					(mid 325.859648 -253.864872)
					(end 323.764656 -251.76988)
				)
				(arc
					(start 323.764656 -251.76988)
					(mid 325.859648 -249.674888)
					(end 327.95464 -251.76988)
				)
			)
		)
	)
	(zone
		(layer "F.Cu")
		(hatch none 0.5)
		(connect_pads
			(clearance 0)
		)
		(min_thickness 0.25)
		(keepout
			(tracks allowed)
			(vias allowed)
			(pads allowed)
			(copperpour allowed)
			(footprints allowed)
		)
		(placement
			(enabled no)
			(sheetname "")
		)
		(fill
			(thermal_gap 0.5)
			(thermal_bridge_width 0.5)
			(island_removal_mode 0)
		)
		(polygon
			(pts
				(xy 44.47286 -147.112228) (xy 44.47286 -146.461988) (xy 47.12208 -146.461988) (xy 47.12208 -147.112228)
			)
		)
	)
	(zone
		(layer "F.Cu")
		(hatch none 0.5)
		(connect_pads
			(clearance 0)
		)
		(min_thickness 0.25)
		(keepout
			(tracks allowed)
			(vias allowed)
			(pads allowed)
			(copperpour allowed)
			(footprints allowed)
		)
		(placement
			(enabled no)
			(sheetname "")
		)
		(fill
			(thermal_gap 0.5)
			(thermal_bridge_width 0.5)
			(island_removal_mode 0)
		)
		(polygon
			(pts
				(xy 195.510658 -197.854824) (xy 195.510658 -197.626224) (xy 197.542658 -197.626224) (xy 197.542658 -197.854824)
			)
		)
	)
	(zone
		(layer "F.Cu")
		(hatch none 0.5)
		(connect_pads
			(clearance 0)
		)
		(min_thickness 0.25)
		(keepout
			(tracks allowed)
			(vias allowed)
			(pads allowed)
			(copperpour allowed)
			(footprints not_allowed)
		)
		(placement
			(enabled no)
			(sheetname "")
		)
		(fill
			(thermal_gap 0.5)
			(thermal_bridge_width 0.5)
			(island_removal_mode 0)
		)
		(polygon
			(pts
				(arc
					(start 244.650006 -272.50009)
					(mid 236.650022 -280.500074)
					(end 228.650038 -272.50009)
				)
				(arc
					(start 228.650038 -272.50009)
					(mid 236.650022 -264.500106)
					(end 244.650006 -272.50009)
				)
			)
		)
	)
	(zone
		(layer "F.Cu")
		(hatch none 0.5)
		(connect_pads
			(clearance 0)
		)
		(min_thickness 0.25)
		(keepout
			(tracks allowed)
			(vias allowed)
			(pads allowed)
			(copperpour allowed)
			(footprints allowed)
		)
		(placement
			(enabled no)
			(sheetname "")
		)
		(fill
			(thermal_gap 0.5)
			(thermal_bridge_width 0.5)
			(island_removal_mode 0)
		)
		(polygon
			(pts
				(xy 274.143978 -297.416474) (xy 274.143978 -296.972736) (xy 276.469094 -296.972736) (xy 276.469094 -297.416474)
			)
		)
	)
	(zone
		(layer "F.Cu")
		(hatch none 0.5)
		(connect_pads
			(clearance 0)
		)
		(min_thickness 0.25)
		(keepout
			(tracks allowed)
			(vias allowed)
			(pads allowed)
			(copperpour allowed)
			(footprints allowed)
		)
		(placement
			(enabled no)
			(sheetname "")
		)
		(fill
			(thermal_gap 0.5)
			(thermal_bridge_width 0.5)
			(island_removal_mode 0)
		)
		(polygon
			(pts
				(xy 63.977012 -210.716622) (xy 63.977012 -210.272884) (xy 66.186812 -210.272884) (xy 66.186812 -210.716622)
			)
		)
	)
	(zone
		(layer "F.Cu")
		(hatch none 0.5)
		(connect_pads
			(clearance 0)
		)
		(min_thickness 0.25)
		(keepout
			(tracks allowed)
			(vias allowed)
			(pads allowed)
			(copperpour allowed)
			(footprints allowed)
		)
		(placement
			(enabled no)
			(sheetname "")
		)
		(fill
			(thermal_gap 0.5)
			(thermal_bridge_width 0.5)
			(island_removal_mode 0)
		)
		(polygon
			(pts
				(xy 304.319178 -213.266528) (xy 304.319178 -212.82279) (xy 306.644294 -212.82279) (xy 306.644294 -213.266528)
			)
		)
	)
	(zone
		(layer "F.Cu")
		(hatch none 0.5)
		(connect_pads
			(clearance 0)
		)
		(min_thickness 0.25)
		(keepout
			(tracks allowed)
			(vias allowed)
			(pads allowed)
			(copperpour allowed)
			(footprints allowed)
		)
		(placement
			(enabled no)
			(sheetname "")
		)
		(fill
			(thermal_gap 0.5)
			(thermal_bridge_width 0.5)
			(island_removal_mode 0)
		)
		(polygon
			(pts
				(xy 428.487078 -361.958128) (xy 424.951398 -361.958128) (xy 424.951398 -359.875328) (xy 428.487078 -359.875328)
			)
		)
	)
	(zone
		(layer "F.Cu")
		(hatch none 0.5)
		(connect_pads
			(clearance 0)
		)
		(min_thickness 0.25)
		(keepout
			(tracks not_allowed)
			(vias allowed)
			(pads allowed)
			(copperpour not_allowed)
			(footprints allowed)
		)
		(placement
			(enabled no)
			(sheetname "")
		)
		(fill
			(thermal_gap 0.5)
			(thermal_bridge_width 0.5)
			(island_removal_mode 0)
		)
		(polygon
			(pts
				(arc
					(start 263.649968 -22.29993)
					(mid 265.649964 -20.299934)
					(end 267.64996 -22.29993)
				)
				(arc
					(start 267.64996 -22.29993)
					(mid 265.649964 -24.299926)
					(end 263.649968 -22.29993)
				)
			)
		)
	)
	(zone
		(layer "F.Cu")
		(hatch none 0.5)
		(connect_pads
			(clearance 0)
		)
		(min_thickness 0.25)
		(keepout
			(tracks allowed)
			(vias allowed)
			(pads allowed)
			(copperpour allowed)
			(footprints not_allowed)
		)
		(placement
			(enabled no)
			(sheetname "")
		)
		(fill
			(thermal_gap 0.5)
			(thermal_bridge_width 0.5)
			(island_removal_mode 0)
		)
		(polygon
			(pts
				(xy 220.300042 -14.617954) (xy 228.300026 -14.617954) (xy 228.300026 -25.617932) (xy 220.300042 -25.617932)
			)
		)
	)
	(zone
		(layer "F.Cu")
		(hatch none 0.5)
		(connect_pads
			(clearance 0)
		)
		(min_thickness 0.25)
		(keepout
			(tracks allowed)
			(vias allowed)
			(pads allowed)
			(copperpour allowed)
			(footprints allowed)
		)
		(placement
			(enabled no)
			(sheetname "")
		)
		(fill
			(thermal_gap 0.5)
			(thermal_bridge_width 0.5)
			(island_removal_mode 0)
		)
		(polygon
			(pts
				(xy 176.979326 -278.37638) (xy 179.011326 -278.37638) (xy 179.011326 -278.60498) (xy 176.979326 -278.60498)
				(xy 176.843182 -278.60498) (xy 176.796192 -278.60498) (xy 176.796192 -278.37638) (xy 176.843182 -278.37638)
			)
		)
	)
	(zone
		(layer "F.Cu")
		(hatch none 0.5)
		(connect_pads
			(clearance 0)
		)
		(min_thickness 0.25)
		(keepout
			(tracks allowed)
			(vias allowed)
			(pads allowed)
			(copperpour allowed)
			(footprints allowed)
		)
		(placement
			(enabled no)
			(sheetname "")
		)
		(fill
			(thermal_gap 0.5)
			(thermal_bridge_width 0.5)
			(island_removal_mode 0)
		)
		(polygon
			(pts
				(xy 210.598258 -203.805028) (xy 210.598258 -203.576428) (xy 212.630258 -203.576428) (xy 212.630258 -203.805028)
			)
		)
	)
	(zone
		(layer "F.Cu")
		(hatch none 0.5)
		(connect_pads
			(clearance 0)
		)
		(min_thickness 0.25)
		(keepout
			(tracks allowed)
			(vias allowed)
			(pads allowed)
			(copperpour allowed)
			(footprints allowed)
		)
		(placement
			(enabled no)
			(sheetname "")
		)
		(fill
			(thermal_gap 0.5)
			(thermal_bridge_width 0.5)
			(island_removal_mode 0)
		)
		(polygon
			(pts
				(xy 11.11631 -231.966516) (xy 11.11631 -231.522778) (xy 13.441426 -231.522778) (xy 13.441426 -231.966516)
			)
		)
	)
	(zone
		(layer "F.Cu")
		(hatch none 0.5)
		(connect_pads
			(clearance 0)
		)
		(min_thickness 0.25)
		(keepout
			(tracks allowed)
			(vias allowed)
			(pads allowed)
			(copperpour allowed)
			(footprints allowed)
		)
		(placement
			(enabled no)
			(sheetname "")
		)
		(fill
			(thermal_gap 0.5)
			(thermal_bridge_width 0.5)
			(island_removal_mode 0)
		)
		(polygon
			(pts
				(xy 127.508 -324.729348) (xy 127.508 -322.387468) (xy 131.8768 -322.387468) (xy 131.8768 -324.729348)
			)
		)
	)
	(zone
		(layer "F.Cu")
		(hatch none 0.5)
		(connect_pads
			(clearance 0)
		)
		(min_thickness 0.25)
		(keepout
			(tracks allowed)
			(vias allowed)
			(pads allowed)
			(copperpour allowed)
			(footprints allowed)
		)
		(placement
			(enabled no)
			(sheetname "")
		)
		(fill
			(thermal_gap 0.5)
			(thermal_bridge_width 0.5)
			(island_removal_mode 0)
		)
		(polygon
			(pts
				(xy 176.979326 -197.626478) (xy 179.011326 -197.626478) (xy 179.011326 -197.855078) (xy 176.979326 -197.855078)
				(xy 176.843182 -197.855078) (xy 176.796192 -197.855078) (xy 176.796192 -197.626478) (xy 176.843182 -197.626478)
			)
		)
	)
	(zone
		(layer "F.Cu")
		(hatch none 0.5)
		(connect_pads
			(clearance 0)
		)
		(min_thickness 0.25)
		(keepout
			(tracks allowed)
			(vias allowed)
			(pads allowed)
			(copperpour allowed)
			(footprints allowed)
		)
		(placement
			(enabled no)
			(sheetname "")
		)
		(fill
			(thermal_gap 0.5)
			(thermal_bridge_width 0.5)
			(island_removal_mode 0)
		)
		(polygon
			(pts
				(xy 274.143978 -288.06648) (xy 274.143978 -287.622742) (xy 276.469094 -287.622742) (xy 276.469094 -288.06648)
			)
		)
	)
	(zone
		(layer "F.Cu")
		(hatch none 0.5)
		(connect_pads
			(clearance 0)
		)
		(min_thickness 0.25)
		(keepout
			(tracks allowed)
			(vias allowed)
			(pads allowed)
			(copperpour allowed)
			(footprints allowed)
		)
		(placement
			(enabled no)
			(sheetname "")
		)
		(fill
			(thermal_gap 0.5)
			(thermal_bridge_width 0.5)
			(island_removal_mode 0)
		)
		(polygon
			(pts
				(xy 311.89168 -203.916534) (xy 311.89168 -203.472796) (xy 314.10148 -203.472796) (xy 314.10148 -203.916534)
			)
		)
	)
	(zone
		(layer "F.Cu")
		(hatch none 0.5)
		(connect_pads
			(clearance 0)
		)
		(min_thickness 0.25)
		(keepout
			(tracks allowed)
			(vias allowed)
			(pads allowed)
			(copperpour allowed)
			(footprints allowed)
		)
		(placement
			(enabled no)
			(sheetname "")
		)
		(fill
			(thermal_gap 0.5)
			(thermal_bridge_width 0.5)
			(island_removal_mode 0)
		)
		(polygon
			(pts
				(xy 192.066926 -293.906956) (xy 194.098926 -293.906956) (xy 194.098926 -293.678356) (xy 192.066926 -293.678356)
				(xy 191.935608 -293.678356) (xy 191.9097 -293.678356) (xy 191.9097 -293.906956) (xy 191.935608 -293.906956)
			)
		)
	)
	(zone
		(layer "F.Cu")
		(hatch none 0.5)
		(connect_pads
			(clearance 0)
		)
		(min_thickness 0.25)
		(keepout
			(tracks allowed)
			(vias allowed)
			(pads allowed)
			(copperpour allowed)
			(footprints allowed)
		)
		(placement
			(enabled no)
			(sheetname "")
		)
		(fill
			(thermal_gap 0.5)
			(thermal_bridge_width 0.5)
			(island_removal_mode 0)
		)
		(polygon
			(pts
				(xy 210.598258 -291.355018) (xy 210.598258 -291.126418) (xy 212.630258 -291.126418) (xy 212.630258 -291.355018)
			)
		)
	)
	(zone
		(layer "F.Cu")
		(hatch none 0.5)
		(connect_pads
			(clearance 0)
		)
		(min_thickness 0.25)
		(keepout
			(tracks allowed)
			(vias allowed)
			(pads allowed)
			(copperpour allowed)
			(footprints allowed)
		)
		(placement
			(enabled no)
			(sheetname "")
		)
		(fill
			(thermal_gap 0.5)
			(thermal_bridge_width 0.5)
			(island_removal_mode 0)
		)
		(polygon
			(pts
				(xy 363.89691 -333.586582) (xy 360.36123 -333.586582) (xy 360.36123 -331.503782) (xy 363.89691 -331.503782)
			)
		)
	)
	(zone
		(layer "F.Cu")
		(hatch none 0.5)
		(connect_pads
			(clearance 0)
		)
		(min_thickness 0.25)
		(keepout
			(tracks allowed)
			(vias allowed)
			(pads allowed)
			(copperpour allowed)
			(footprints allowed)
		)
		(placement
			(enabled no)
			(sheetname "")
		)
		(fill
			(thermal_gap 0.5)
			(thermal_bridge_width 0.5)
			(island_removal_mode 0)
		)
		(polygon
			(pts
				(xy 44.735242 -277.016464) (xy 44.735242 -276.572726) (xy 47.060358 -276.572726) (xy 47.060358 -277.016464)
			)
		)
	)
	(zone
		(layer "F.Cu")
		(hatch none 0.5)
		(connect_pads
			(clearance 0)
		)
		(min_thickness 0.25)
		(keepout
			(tracks allowed)
			(vias allowed)
			(pads allowed)
			(copperpour allowed)
			(footprints allowed)
		)
		(placement
			(enabled no)
			(sheetname "")
		)
		(fill
			(thermal_gap 0.5)
			(thermal_bridge_width 0.5)
			(island_removal_mode 0)
		)
		(polygon
			(pts
				(xy 44.735242 -245.566438) (xy 44.735242 -245.1227) (xy 47.060358 -245.1227) (xy 47.060358 -245.566438)
			)
		)
	)
	(zone
		(layer "F.Cu")
		(hatch none 0.5)
		(connect_pads
			(clearance 0)
		)
		(min_thickness 0.25)
		(keepout
			(tracks allowed)
			(vias allowed)
			(pads allowed)
			(copperpour allowed)
			(footprints allowed)
		)
		(placement
			(enabled no)
			(sheetname "")
		)
		(fill
			(thermal_gap 0.5)
			(thermal_bridge_width 0.5)
			(island_removal_mode 0)
		)
		(polygon
			(pts
				(xy 307.76291 -280.416508) (xy 307.76291 -279.97277) (xy 310.088026 -279.97277) (xy 310.088026 -280.416508)
			)
		)
	)
	(zone
		(layer "F.Cu")
		(hatch none 0.5)
		(connect_pads
			(clearance 0)
		)
		(min_thickness 0.25)
		(keepout
			(tracks not_allowed)
			(vias allowed)
			(pads allowed)
			(copperpour not_allowed)
			(footprints allowed)
		)
		(placement
			(enabled no)
			(sheetname "")
		)
		(fill
			(thermal_gap 0.5)
			(thermal_bridge_width 0.5)
			(island_removal_mode 0)
		)
		(polygon
			(pts
				(xy 135.755888 -344.954352) (xy 135.998204 -344.954352) (xy 135.998204 -344.894408) (xy 135.755888 -344.894408)
			)
		)
	)
	(zone
		(layer "F.Cu")
		(hatch none 0.5)
		(connect_pads
			(clearance 0)
		)
		(min_thickness 0.25)
		(keepout
			(tracks allowed)
			(vias allowed)
			(pads allowed)
			(copperpour allowed)
			(footprints allowed)
		)
		(placement
			(enabled no)
			(sheetname "")
		)
		(fill
			(thermal_gap 0.5)
			(thermal_bridge_width 0.5)
			(island_removal_mode 0)
		)
		(polygon
			(pts
				(xy 157.791658 -266.704826) (xy 157.791658 -266.476226) (xy 159.823658 -266.476226) (xy 159.823658 -266.704826)
			)
		)
	)
	(zone
		(layer "F.Cu")
		(hatch none 0.5)
		(connect_pads
			(clearance 0)
		)
		(min_thickness 0.25)
		(keepout
			(tracks allowed)
			(vias allowed)
			(pads allowed)
			(copperpour allowed)
			(footprints allowed)
		)
		(placement
			(enabled no)
			(sheetname "")
		)
		(fill
			(thermal_gap 0.5)
			(thermal_bridge_width 0.5)
			(island_removal_mode 0)
		)
		(polygon
			(pts
				(xy 289.231578 -211.566506) (xy 289.231578 -211.122768) (xy 291.556694 -211.122768) (xy 291.556694 -211.566506)
			)
		)
	)
	(zone
		(layer "F.Cu")
		(hatch none 0.5)
		(connect_pads
			(clearance 0)
		)
		(min_thickness 0.25)
		(keepout
			(tracks allowed)
			(vias allowed)
			(pads allowed)
			(copperpour allowed)
			(footprints not_allowed)
		)
		(placement
			(enabled no)
			(sheetname "")
		)
		(fill
			(thermal_gap 0.5)
			(thermal_bridge_width 0.5)
			(island_removal_mode 0)
		)
		(polygon
			(pts
				(arc
					(start 244.650006 -192.499996)
					(mid 236.650022 -200.49998)
					(end 228.650038 -192.499996)
				)
				(arc
					(start 228.650038 -192.499996)
					(mid 236.650022 -184.500012)
					(end 244.650006 -192.499996)
				)
			)
		)
	)
	(zone
		(layer "F.Cu")
		(hatch none 0.5)
		(connect_pads
			(clearance 0)
		)
		(min_thickness 0.25)
		(keepout
			(tracks allowed)
			(vias allowed)
			(pads allowed)
			(copperpour allowed)
			(footprints allowed)
		)
		(placement
			(enabled no)
			(sheetname "")
		)
		(fill
			(thermal_gap 0.5)
			(thermal_bridge_width 0.5)
			(island_removal_mode 0)
		)
		(polygon
			(pts
				(xy 11.11631 -214.96655) (xy 11.11631 -214.522812) (xy 13.441426 -214.522812) (xy 13.441426 -214.96655)
			)
		)
	)
	(zone
		(layer "F.Cu")
		(hatch none 0.5)
		(connect_pads
			(clearance 0)
		)
		(min_thickness 0.25)
		(keepout
			(tracks allowed)
			(vias allowed)
			(pads allowed)
			(copperpour allowed)
			(footprints allowed)
		)
		(placement
			(enabled no)
			(sheetname "")
		)
		(fill
			(thermal_gap 0.5)
			(thermal_bridge_width 0.5)
			(island_removal_mode 0)
		)
		(polygon
			(pts
				(xy 76.13142 -150.144988) (xy 76.13142 -145.143728) (xy 78.81366 -145.143728) (xy 78.81366 -150.144988)
			)
		)
	)
	(zone
		(layer "F.Cu")
		(hatch none 0.5)
		(connect_pads
			(clearance 0)
		)
		(min_thickness 0.25)
		(keepout
			(tracks allowed)
			(vias allowed)
			(pads allowed)
			(copperpour allowed)
			(footprints allowed)
		)
		(placement
			(enabled no)
			(sheetname "")
		)
		(fill
			(thermal_gap 0.5)
			(thermal_bridge_width 0.5)
			(island_removal_mode 0)
		)
		(polygon
			(pts
				(xy 409.831794 -291.355018) (xy 409.831794 -291.126418) (xy 411.863794 -291.126418) (xy 411.863794 -291.355018)
			)
		)
	)
	(zone
		(layer "F.Cu")
		(hatch none 0.5)
		(connect_pads
			(clearance 0)
		)
		(min_thickness 0.25)
		(keepout
			(tracks allowed)
			(vias allowed)
			(pads allowed)
			(copperpour allowed)
			(footprints allowed)
		)
		(placement
			(enabled no)
			(sheetname "")
		)
		(fill
			(thermal_gap 0.5)
			(thermal_bridge_width 0.5)
			(island_removal_mode 0)
		)
		(polygon
			(pts
				(xy 388.919212 -245.166388) (xy 388.741412 -245.344188) (xy 388.337806 -245.344442) (xy 388.337806 -246.68226)
				(xy 388.371588 -246.716042) (xy 388.746238 -246.716042) (xy 388.786116 -246.75592) (xy 388.786116 -247.090946)
				(xy 388.734554 -247.142508) (xy 388.734554 -247.334786) (xy 389.59917 -248.199402) (xy 389.59917 -248.423684)
				(xy 389.597392 -248.425462) (xy 389.732266 -248.560336) (xy 389.732266 -248.675144) (xy 388.163562 -250.243848)
				(xy 386.835142 -250.243848) (xy 386.803138 -250.275852) (xy 386.803138 -250.432316) (xy 386.547106 -250.688348)
				(xy 385.182872 -250.688348) (xy 385.139438 -250.731782) (xy 385.139438 -251.022358) (xy 386.432298 -251.022358)
				(xy 386.559298 -250.895358) (xy 389.835898 -250.895104) (xy 390.750298 -249.980704) (xy 390.750298 -249.966988)
				(xy 392.70559 -249.966988) (xy 392.93419 -249.738388) (xy 394.53439 -249.738388) (xy 394.631926 -249.738388)
				(xy 395.203934 -249.16638) (xy 395.487398 -249.16638) (xy 395.757146 -248.896632) (xy 396.156434 -248.896632)
				(xy 396.26159 -249.001788) (xy 396.369794 -249.109992) (xy 396.501366 -249.109992) (xy 396.709646 -248.901712)
				(xy 396.709646 -248.637552) (xy 396.567406 -248.495312) (xy 396.567406 -247.857772) (xy 396.511526 -247.801892)
				(xy 395.391386 -247.801892) (xy 395.388846 -247.804432) (xy 395.236446 -247.804432) (xy 394.960602 -247.528588)
				(xy 394.83919 -247.528588) (xy 394.758926 -247.528588) (xy 393.920726 -246.690388) (xy 393.79779 -246.690388)
				(xy 393.689586 -246.690388) (xy 393.332716 -246.333518) (xy 393.059666 -246.333518) (xy 392.803126 -246.076978)
				(xy 392.803126 -246.018812) (xy 392.747246 -245.962932) (xy 392.728196 -245.962932) (xy 392.171936 -245.406672)
				(xy 392.171936 -245.293388) (xy 392.171936 -245.250462) (xy 391.964926 -245.043452) (xy 391.922 -245.043452)
				(xy 389.042148 -245.043452)
			)
		)
	)
	(zone
		(layer "F.Cu")
		(hatch none 0.5)
		(connect_pads
			(clearance 0)
		)
		(min_thickness 0.25)
		(keepout
			(tracks allowed)
			(vias allowed)
			(pads allowed)
			(copperpour allowed)
			(footprints allowed)
		)
		(placement
			(enabled no)
			(sheetname "")
		)
		(fill
			(thermal_gap 0.5)
			(thermal_bridge_width 0.5)
			(island_removal_mode 0)
		)
		(polygon
			(pts
				(xy 11.11631 -284.666436) (xy 11.11631 -284.222698) (xy 13.441426 -284.222698) (xy 13.441426 -284.666436)
			)
		)
	)
	(zone
		(layer "F.Cu")
		(hatch none 0.5)
		(connect_pads
			(clearance 0)
		)
		(min_thickness 0.25)
		(keepout
			(tracks allowed)
			(vias allowed)
			(pads allowed)
			(copperpour allowed)
			(footprints allowed)
		)
		(placement
			(enabled no)
			(sheetname "")
		)
		(fill
			(thermal_gap 0.5)
			(thermal_bridge_width 0.5)
			(island_removal_mode 0)
		)
		(polygon
			(pts
				(xy 386.271516 -280.37409) (xy 385.680712 -280.37409) (xy 384.313176 -279.006554) (xy 384.312922 -275.18995)
				(xy 383.847086 -274.72386) (xy 383.847086 -274.702524) (xy 383.847086 -253.71806) (xy 383.582672 -253.453646)
				(xy 383.14376 -253.014734) (xy 381.822198 -253.014734) (xy 381.136906 -252.329442) (xy 379.983238 -251.175774)
				(xy 379.983238 -248.675398) (xy 380.811532 -247.847104) (xy 382.843532 -247.847104) (xy 383.750566 -246.94007)
				(xy 383.750058 -227.200206) (xy 385.74726 -225.203004) (xy 386.593588 -225.203004) (xy 386.598668 -225.197924)
				(xy 387.046978 -225.197924) (xy 387.17093 -225.073972) (xy 387.25729 -224.987612) (xy 387.34238 -224.987612)
				(xy 388.115556 -225.760788) (xy 388.115556 -226.114356) (xy 388.00278 -226.227132) (xy 388.00278 -226.264724)
				(xy 388.395464 -226.657408) (xy 388.395464 -226.716844) (xy 388.234682 -226.877626) (xy 388.234682 -226.976686)
				(xy 388.58571 -227.327714) (xy 388.58571 -227.40112) (xy 388.37743 -227.6094) (xy 388.37743 -227.692458)
				(xy 388.982458 -228.297486) (xy 388.982458 -228.358954) (xy 388.552182 -228.78923) (xy 388.552182 -228.830886)
				(xy 388.659116 -228.93782) (xy 388.718806 -228.93782) (xy 389.059928 -228.596698) (xy 389.198358 -228.596698)
				(xy 389.672576 -229.070916) (xy 389.672576 -229.233476) (xy 388.508494 -230.397558) (xy 388.508494 -230.500428)
				(xy 389.093456 -231.08539) (xy 389.093456 -231.190546) (xy 388.175246 -232.108756) (xy 388.175246 -232.160318)
				(xy 388.740396 -232.725468) (xy 388.740396 -232.866438) (xy 388.4549 -233.151934) (xy 388.4549 -233.734864)
				(xy 388.37743 -233.812334) (xy 388.37743 -235.059474) (xy 388.435088 -235.117132) (xy 389.095234 -235.117132)
				(xy 389.172704 -235.194602) (xy 389.172704 -236.441996) (xy 389.202422 -236.471714) (xy 389.202422 -237.090458)
				(xy 389.176768 -237.116112) (xy 388.97052 -237.116112) (xy 388.785862 -237.116112) (xy 388.747762 -237.154212)
				(xy 388.747762 -237.559596) (xy 388.858252 -237.670086) (xy 388.956042 -237.670086) (xy 388.97814 -237.692184)
				(xy 388.97814 -238.494824) (xy 388.985506 -238.50219) (xy 389.222234 -238.50219) (xy 389.317484 -238.59744)
				(xy 389.317484 -238.829596) (xy 389.055864 -239.091216) (xy 388.86765 -239.091216) (xy 388.20725 -239.751616)
				(xy 388.20725 -239.886744) (xy 388.442962 -240.122456) (xy 388.442962 -240.207546) (xy 388.19709 -240.453418)
				(xy 388.19709 -240.54054) (xy 388.72668 -241.07013) (xy 388.7724 -241.07013) (xy 389.476488 -240.366042)
				(xy 389.900414 -240.366042) (xy 389.954262 -240.41989) (xy 389.954262 -240.983008) (xy 389.922512 -241.014758)
				(xy 389.642858 -241.014758) (xy 388.583678 -242.073938) (xy 388.583678 -242.115086) (xy 388.923022 -242.45443)
				(xy 388.923022 -242.614958) (xy 388.189216 -243.348764) (xy 388.189216 -244.939566) (xy 388.337806 -245.088156)
				(xy 388.337806 -246.68226) (xy 388.371588 -246.716042) (xy 388.746238 -246.716042) (xy 388.786116 -246.75592)
				(xy 388.786116 -247.090946) (xy 388.734554 -247.142508) (xy 388.734554 -247.334786) (xy 389.59917 -248.199402)
				(xy 389.59917 -248.340118) (xy 389.597392 -248.341896) (xy 389.597392 -248.425462) (xy 389.732266 -248.560336)
				(xy 389.732266 -248.675144) (xy 388.163562 -250.243848) (xy 386.835142 -250.243848) (xy 386.803138 -250.275852)
				(xy 386.803138 -250.432316) (xy 386.547106 -250.688348) (xy 385.182872 -250.688348) (xy 385.139438 -250.731782)
				(xy 385.139438 -250.98756) (xy 385.10464 -251.022358) (xy 385.010406 -251.022358) (xy 384.706622 -251.022358)
				(xy 384.524504 -250.84024) (xy 384.056128 -250.84024) (xy 383.655316 -250.439428) (xy 383.655316 -250.109228)
				(xy 383.501392 -249.955304) (xy 380.589028 -249.955304) (xy 380.486158 -250.058174) (xy 380.486158 -250.244356)
				(xy 380.536196 -250.244356) (xy 380.936246 -250.644406) (xy 381.248412 -250.8631) (xy 382.852676 -251.705618)
				(xy 383.297176 -251.900944) (xy 383.297176 -251.901452) (xy 383.360676 -251.940822) (xy 383.360676 -252.153674)
				(xy 383.41173 -252.204728) (xy 383.929128 -252.521212) (xy 384.47472 -252.654562) (xy 384.5052 -252.685042)
				(xy 384.5052 -252.854968) (xy 384.781552 -253.13132) (xy 384.831336 -253.13132) (xy 386.523484 -253.13132)
				(xy 388.41934 -253.527814) (xy 388.43712 -253.545594) (xy 388.43712 -253.844298) (xy 388.40791 -253.873508)
				(xy 388.40791 -253.910592) (xy 388.469378 -253.97206) (xy 388.588504 -253.97206) (xy 388.884922 -254.268478)
				(xy 388.884922 -254.533908) (xy 388.835646 -254.583184) (xy 388.327646 -254.583184) (xy 388.314184 -254.596646)
				(xy 388.314184 -255.411732) (xy 388.187184 -255.538732) (xy 388.042658 -255.538732) (xy 387.91769 -255.6637)
				(xy 387.91769 -255.852168) (xy 388.014464 -255.948942) (xy 388.014464 -257.549904) (xy 388.991094 -258.52628)
				(xy 388.991094 -258.570476) (xy 389.982202 -259.561838) (xy 390.007602 -259.587238) (xy 390.007602 -259.736844)
				(xy 389.174736 -260.56971) (xy 389.174736 -260.595618) (xy 390.37641 -261.797292) (xy 390.37641 -261.880858)
				(xy 389.9662 -262.291068) (xy 389.900668 -262.291068) (xy 389.66267 -262.05307) (xy 389.263382 -261.653782)
				(xy 389.224266 -261.653782) (xy 388.92861 -261.949438) (xy 388.92861 -262.025638) (xy 389.02767 -262.124698)
				(xy 389.02767 -262.259826) (xy 388.990332 -262.297164) (xy 388.19328 -263.094216) (xy 388.19328 -263.254744)
				(xy 389.311642 -264.373106) (xy 389.311642 -264.537952) (xy 388.716774 -265.13282) (xy 388.558024 -265.13282)
				(xy 388.082028 -264.656824) (xy 388.018782 -264.656824) (xy 387.887718 -264.787888) (xy 387.887718 -264.859262)
				(xy 389.08355 -266.055094) (xy 389.08355 -266.261088) (xy 388.359904 -266.984734) (xy 388.359904 -267.028676)
				(xy 388.598664 -267.267436) (xy 388.598664 -267.32103) (xy 388.39013 -267.529564) (xy 388.258812 -267.529564)
				(xy 388.054596 -267.325348) (xy 388.03326 -267.325348) (xy 387.310884 -268.047724) (xy 387.310884 -268.095476)
				(xy 389.107426 -269.892018) (xy 389.107426 -270.023082) (xy 388.770114 -270.360394) (xy 388.770114 -270.425672)
				(xy 388.863332 -270.51889) (xy 388.863332 -270.774668) (xy 388.141972 -271.496028) (xy 388.104634 -271.496028)
				(xy 388.04977 -271.44091) (xy 388.036308 -271.427448) (xy 387.898132 -271.427448) (xy 387.5786 -271.74698)
				(xy 387.5786 -271.85112) (xy 387.625336 -271.897856) (xy 387.68274 -271.95526) (xy 387.70306 -271.975834)
				(xy 389.37946 -273.652234) (xy 389.379206 -273.652488) (xy 389.400796 -273.673824) (xy 389.400796 -273.790918)
				(xy 389.2423 -273.949414) (xy 389.14705 -273.949414) (xy 388.302246 -273.10461) (xy 388.282434 -273.10461)
				(xy 388.127748 -273.259296) (xy 388.127748 -273.30908) (xy 388.946898 -274.12823) (xy 388.946898 -274.258786)
				(xy 388.546086 -274.659598) (xy 388.546086 -274.812252) (xy 388.060184 -275.298154) (xy 388.060184 -275.313648)
				(xy 388.252462 -275.505926) (xy 388.252462 -275.585428) (xy 387.841998 -275.995892) (xy 387.841998 -276.023578)
				(xy 387.841998 -276.206204) (xy 388.07009 -276.434296) (xy 388.07009 -276.51202) (xy 387.570472 -277.011638)
				(xy 387.570472 -277.161498) (xy 387.570726 -277.161752) (xy 387.13537 -277.597108) (xy 387.13537 -277.605744)
				(xy 387.284214 -277.754588) (xy 387.57479 -278.045164) (xy 387.57479 -278.655018) (xy 387.677406 -278.757634)
				(xy 387.677406 -279.357074) (xy 387.892798 -279.57272) (xy 387.892798 -280.115772) (xy 388.070344 -280.293318)
				(xy 388.070344 -281.069288) (xy 388.070344 -281.161998) (xy 388.054596 -281.177746) (xy 386.927852 -281.177746)
				(xy 386.807456 -281.05735) (xy 386.807456 -280.91003)
			)
		)
	)
	(zone
		(layer "F.Cu")
		(hatch none 0.5)
		(connect_pads
			(clearance 0)
		)
		(min_thickness 0.25)
		(keepout
			(tracks allowed)
			(vias allowed)
			(pads allowed)
			(copperpour allowed)
			(footprints allowed)
		)
		(placement
			(enabled no)
			(sheetname "")
		)
		(fill
			(thermal_gap 0.5)
			(thermal_bridge_width 0.5)
			(island_removal_mode 0)
		)
		(polygon
			(pts
				(xy 161.891726 -276.676358) (xy 163.923726 -276.676358) (xy 163.923726 -276.678644) (xy 164.102542 -276.678644)
				(xy 164.102542 -276.91588) (xy 164.240464 -276.91588) (xy 164.283644 -276.95906) (xy 164.283644 -277.091902)
				(xy 164.283644 -277.39594) (xy 164.211 -277.468584) (xy 161.670746 -277.468584) (xy 161.529522 -277.32736)
				(xy 161.529522 -277.130256) (xy 161.611056 -277.048722) (xy 161.611056 -276.676358) (xy 161.708592 -276.676358)
				(xy 161.755582 -276.676358)
			)
		)
	)
	(zone
		(layer "F.Cu")
		(hatch none 0.5)
		(connect_pads
			(clearance 0)
		)
		(min_thickness 0.25)
		(keepout
			(tracks allowed)
			(vias allowed)
			(pads allowed)
			(copperpour allowed)
			(footprints allowed)
		)
		(placement
			(enabled no)
			(sheetname "")
		)
		(fill
			(thermal_gap 0.5)
			(thermal_bridge_width 0.5)
			(island_removal_mode 0)
		)
		(polygon
			(pts
				(xy 63.60922 -167.241728) (xy 63.60922 -162.956748) (xy 65.60566 -162.956748) (xy 65.60566 -167.241728)
			)
		)
	)
	(zone
		(layer "F.Cu")
		(hatch none 0.5)
		(connect_pads
			(clearance 0)
		)
		(min_thickness 0.25)
		(keepout
			(tracks allowed)
			(vias allowed)
			(pads allowed)
			(copperpour allowed)
			(footprints allowed)
		)
		(placement
			(enabled no)
			(sheetname "")
		)
		(fill
			(thermal_gap 0.5)
			(thermal_bridge_width 0.5)
			(island_removal_mode 0)
		)
		(polygon
			(pts
				(xy 304.319178 -207.316578) (xy 304.319178 -206.87284) (xy 306.644294 -206.87284) (xy 306.644294 -207.316578)
			)
		)
	)
	(zone
		(layer "F.Cu")
		(hatch none 0.5)
		(connect_pads
			(clearance 0)
		)
		(min_thickness 0.25)
		(keepout
			(tracks allowed)
			(vias allowed)
			(pads allowed)
			(copperpour allowed)
			(footprints not_allowed)
		)
		(placement
			(enabled no)
			(sheetname "")
		)
		(fill
			(thermal_gap 0.5)
			(thermal_bridge_width 0.5)
			(island_removal_mode 0)
		)
		(polygon
			(pts
				(xy 335.848706 -355.763576) (xy 378.420884 -355.763576) (xy 378.420884 -345.424252)
				(arc
					(start 374.261634 -345.424252)
					(mid 373.342415 -345.043499)
					(end 372.961662 -344.12428)
				)
				(xy 372.961662 -339.691472) (xy 341.879682 -339.691472)
				(arc
					(start 341.879682 -344.12428)
					(mid 341.498929 -345.043499)
					(end 340.57971 -345.424252)
				)
				(xy 335.848706 -345.424252)
			)
		)
	)
	(zone
		(layer "F.Cu")
		(hatch none 0.5)
		(connect_pads
			(clearance 0)
		)
		(min_thickness 0.25)
		(keepout
			(tracks allowed)
			(vias allowed)
			(pads allowed)
			(copperpour allowed)
			(footprints allowed)
		)
		(placement
			(enabled no)
			(sheetname "")
		)
		(fill
			(thermal_gap 0.5)
			(thermal_bridge_width 0.5)
			(island_removal_mode 0)
		)
		(polygon
			(pts
				(xy 195.510658 -211.455) (xy 195.510658 -211.2264) (xy 197.542658 -211.2264) (xy 197.542658 -211.455)
			)
		)
	)
	(zone
		(layer "F.Cu")
		(hatch none 0.5)
		(connect_pads
			(clearance 0)
		)
		(min_thickness 0.25)
		(keepout
			(tracks allowed)
			(vias allowed)
			(pads allowed)
			(copperpour allowed)
			(footprints allowed)
		)
		(placement
			(enabled no)
			(sheetname "")
		)
		(fill
			(thermal_gap 0.5)
			(thermal_bridge_width 0.5)
			(island_removal_mode 0)
		)
		(polygon
			(pts
				(xy 176.979326 -203.576428) (xy 179.011326 -203.576428) (xy 179.011326 -203.805028) (xy 176.979326 -203.805028)
				(xy 176.843182 -203.805028) (xy 176.796192 -203.805028) (xy 176.796192 -203.576428) (xy 176.843182 -203.576428)
			)
		)
	)
	(zone
		(layer "F.Cu")
		(hatch none 0.5)
		(connect_pads
			(clearance 0)
		)
		(min_thickness 0.25)
		(keepout
			(tracks allowed)
			(vias allowed)
			(pads allowed)
			(copperpour allowed)
			(footprints allowed)
		)
		(placement
			(enabled no)
			(sheetname "")
		)
		(fill
			(thermal_gap 0.5)
			(thermal_bridge_width 0.5)
			(island_removal_mode 0)
		)
		(polygon
			(pts
				(xy 41.29151 -219.216478) (xy 41.29151 -218.77274) (xy 43.616626 -218.77274) (xy 43.616626 -219.216478)
			)
		)
	)
	(zone
		(layer "F.Cu")
		(hatch none 0.5)
		(connect_pads
			(clearance 0)
		)
		(min_thickness 0.25)
		(keepout
			(tracks allowed)
			(vias allowed)
			(pads allowed)
			(copperpour allowed)
			(footprints allowed)
		)
		(placement
			(enabled no)
			(sheetname "")
		)
		(fill
			(thermal_gap 0.5)
			(thermal_bridge_width 0.5)
			(island_removal_mode 0)
		)
		(polygon
			(pts
				(xy 409.831794 -310.055006) (xy 409.831794 -309.826406) (xy 411.863794 -309.826406) (xy 411.863794 -310.055006)
			)
		)
	)
	(zone
		(layer "F.Cu")
		(hatch none 0.5)
		(connect_pads
			(clearance 0)
		)
		(min_thickness 0.25)
		(keepout
			(tracks allowed)
			(vias allowed)
			(pads allowed)
			(copperpour allowed)
			(footprints allowed)
		)
		(placement
			(enabled no)
			(sheetname "")
		)
		(fill
			(thermal_gap 0.5)
			(thermal_bridge_width 0.5)
			(island_removal_mode 0)
		)
		(polygon
			(pts
				(xy 26.20391 -316.116462) (xy 26.20391 -315.672724) (xy 28.529026 -315.672724) (xy 28.529026 -316.116462)
			)
		)
	)
	(zone
		(layer "F.Cu")
		(hatch none 0.5)
		(connect_pads
			(clearance 0)
		)
		(min_thickness 0.25)
		(keepout
			(tracks not_allowed)
			(vias allowed)
			(pads allowed)
			(copperpour not_allowed)
			(footprints allowed)
		)
		(placement
			(enabled no)
			(sheetname "")
		)
		(fill
			(thermal_gap 0.5)
			(thermal_bridge_width 0.5)
			(island_removal_mode 0)
		)
		(polygon
			(pts
				(arc
					(start 97.700338 -435.600094)
					(mid 100.500434 -432.799998)
					(end 103.300276 -435.600094)
				)
				(arc
					(start 103.300276 -435.600094)
					(mid 100.500434 -438.399936)
					(end 97.700338 -435.600094)
				)
			)
		)
	)
	(zone
		(layer "F.Cu")
		(hatch none 0.5)
		(connect_pads
			(clearance 0)
		)
		(min_thickness 0.25)
		(keepout
			(tracks allowed)
			(vias allowed)
			(pads allowed)
			(copperpour allowed)
			(footprints allowed)
		)
		(placement
			(enabled no)
			(sheetname "")
		)
		(fill
			(thermal_gap 0.5)
			(thermal_bridge_width 0.5)
			(island_removal_mode 0)
		)
		(polygon
			(pts
				(xy 29.647642 -227.716588) (xy 29.647642 -227.27285) (xy 31.972758 -227.27285) (xy 31.972758 -227.716588)
			)
		)
	)
	(zone
		(layer "F.Cu")
		(hatch none 0.5)
		(connect_pads
			(clearance 0)
		)
		(min_thickness 0.25)
		(keepout
			(tracks allowed)
			(vias allowed)
			(pads allowed)
			(copperpour allowed)
			(footprints allowed)
		)
		(placement
			(enabled no)
			(sheetname "")
		)
		(fill
			(thermal_gap 0.5)
			(thermal_bridge_width 0.5)
			(island_removal_mode 0)
		)
		(polygon
			(pts
				(xy 292.67531 -233.666538) (xy 292.67531 -233.2228) (xy 295.000426 -233.2228) (xy 295.000426 -233.666538)
			)
		)
	)
	(zone
		(layer "F.Cu")
		(hatch none 0.5)
		(connect_pads
			(clearance 0)
		)
		(min_thickness 0.25)
		(keepout
			(tracks allowed)
			(vias allowed)
			(pads allowed)
			(copperpour allowed)
			(footprints allowed)
		)
		(placement
			(enabled no)
			(sheetname "")
		)
		(fill
			(thermal_gap 0.5)
			(thermal_bridge_width 0.5)
			(island_removal_mode 0)
		)
		(polygon
			(pts
				(xy 26.20391 -278.272748) (xy 28.529026 -278.272748) (xy 28.594558 -278.272748) (xy 28.594558 -279.23617)
				(xy 26.069798 -279.23617) (xy 26.069798 -278.272748)
			)
		)
	)
	(zone
		(layer "F.Cu")
		(hatch none 0.5)
		(connect_pads
			(clearance 0)
		)
		(min_thickness 0.25)
		(keepout
			(tracks allowed)
			(vias allowed)
			(pads allowed)
			(copperpour allowed)
			(footprints allowed)
		)
		(placement
			(enabled no)
			(sheetname "")
		)
		(fill
			(thermal_gap 0.5)
			(thermal_bridge_width 0.5)
			(island_removal_mode 0)
		)
		(polygon
			(pts
				(xy 455.094594 -225.67646) (xy 457.126594 -225.67646) (xy 457.126594 -225.90506) (xy 455.094594 -225.90506)
				(xy 454.95845 -225.90506) (xy 454.91146 -225.90506) (xy 454.91146 -225.67646) (xy 454.95845 -225.67646)
			)
		)
	)
	(zone
		(layer "F.Cu")
		(hatch none 0.5)
		(connect_pads
			(clearance 0)
		)
		(min_thickness 0.25)
		(keepout
			(tracks allowed)
			(vias allowed)
			(pads allowed)
			(copperpour allowed)
			(footprints allowed)
		)
		(placement
			(enabled no)
			(sheetname "")
		)
		(fill
			(thermal_gap 0.5)
			(thermal_bridge_width 0.5)
			(island_removal_mode 0)
		)
		(polygon
			(pts
				(xy 176.979326 -308.126384) (xy 179.011326 -308.126384) (xy 179.011326 -308.354984) (xy 176.979326 -308.354984)
				(xy 176.843182 -308.354984) (xy 176.796192 -308.354984) (xy 176.796192 -308.126384) (xy 176.843182 -308.126384)
			)
		)
	)
	(zone
		(layer "F.Cu")
		(hatch none 0.5)
		(connect_pads
			(clearance 0)
		)
		(min_thickness 0.25)
		(keepout
			(tracks allowed)
			(vias allowed)
			(pads allowed)
			(copperpour allowed)
			(footprints allowed)
		)
		(placement
			(enabled no)
			(sheetname "")
		)
		(fill
			(thermal_gap 0.5)
			(thermal_bridge_width 0.5)
			(island_removal_mode 0)
		)
		(polygon
			(pts
				(xy 210.598258 -306.654962) (xy 210.598258 -306.426362) (xy 212.630258 -306.426362) (xy 212.630258 -306.654962)
			)
		)
	)
	(zone
		(layer "F.Cu")
		(hatch none 0.5)
		(connect_pads
			(clearance 0)
		)
		(min_thickness 0.25)
		(keepout
			(tracks allowed)
			(vias allowed)
			(pads allowed)
			(copperpour allowed)
			(footprints allowed)
		)
		(placement
			(enabled no)
			(sheetname "")
		)
		(fill
			(thermal_gap 0.5)
			(thermal_bridge_width 0.5)
			(island_removal_mode 0)
		)
		(polygon
			(pts
				(xy 405.731726 -234.176316) (xy 407.763726 -234.176316) (xy 407.911554 -234.176316) (xy 407.911554 -234.892342)
				(xy 405.562054 -234.892342) (xy 405.562054 -234.176316)
			)
		)
	)
	(zone
		(layer "F.Cu")
		(hatch none 0.5)
		(connect_pads
			(clearance 0)
		)
		(min_thickness 0.25)
		(keepout
			(tracks allowed)
			(vias allowed)
			(pads allowed)
			(copperpour allowed)
			(footprints allowed)
		)
		(placement
			(enabled no)
			(sheetname "")
		)
		(fill
			(thermal_gap 0.5)
			(thermal_bridge_width 0.5)
			(island_removal_mode 0)
		)
		(polygon
			(pts
				(xy 334.637634 -251.86005) (xy 335.90357 -250.594114) (xy 335.903062 -229.543102) (xy 334.33004 -227.97008)
				(xy 332.909926 -227.97008) (xy 332.337918 -227.398072) (xy 332.337918 -223.591628) (xy 332.98892 -222.940626)
				(xy 335.355692 -222.940626) (xy 335.819496 -222.476822) (xy 335.819496 -219.715842) (xy 334.763872 -218.660218)
				(xy 334.383126 -218.660218) (xy 333.760572 -218.037664) (xy 333.755492 -218.037664) (xy 333.450692 -217.732864)
				(xy 333.435706 -217.717878) (xy 333.37754 -217.717878) (xy 332.990698 -218.10472) (xy 332.990698 -218.44508)
				(xy 331.705712 -219.730066) (xy 331.698854 -219.730066) (xy 331.531722 -219.562934) (xy 331.425296 -219.562934)
				(xy 331.055472 -219.932758) (xy 331.055472 -220.028008) (xy 331.137006 -220.109542) (xy 332.06436 -221.036896)
				(xy 331.261974 -221.839282) (xy 331.261974 -221.937326) (xy 331.263498 -221.938596) (xy 331.263498 -222.420688)
				(xy 331.339698 -222.496888) (xy 331.796898 -222.954088) (xy 331.796898 -227.70465) (xy 331.99705 -227.904802)
				(xy 331.99705 -228.773228) (xy 331.904086 -228.866192) (xy 331.630528 -228.866192) (xy 331.22108 -229.27564)
				(xy 331.22108 -229.35946) (xy 331.291184 -229.429564) (xy 331.722476 -229.860856) (xy 331.722476 -230.785162)
				(xy 331.309472 -231.198166) (xy 331.309472 -232.96118) (xy 331.386942 -233.03865) (xy 331.593952 -233.03865)
				(xy 331.74051 -233.03865) (xy 331.753972 -233.052112) (xy 331.753972 -233.610658) (xy 331.679296 -233.685334)
				(xy 331.458824 -233.685334) (xy 331.331062 -233.813096) (xy 331.331062 -237.449868) (xy 331.373734 -237.49254)
				(xy 331.441552 -237.49254) (xy 331.931518 -237.49254) (xy 331.931518 -237.639352) (xy 331.979524 -237.687358)
				(xy 331.979524 -238.242348) (xy 331.796898 -238.424974) (xy 331.796898 -238.722408) (xy 331.384656 -239.13465)
				(xy 331.20965 -239.13465) (xy 330.678282 -239.666018) (xy 330.678282 -241.113818) (xy 331.669898 -242.105434)
				(xy 331.669898 -244.758972) (xy 331.959204 -244.758972) (xy 331.959204 -245.9228) (xy 331.667866 -245.9228)
				(xy 331.667866 -247.802654) (xy 331.840332 -247.97512) (xy 331.840332 -248.447052) (xy 331.56271 -248.724674)
				(xy 331.56271 -249.268234) (xy 331.57668 -249.282204) (xy 331.707744 -249.282204) (xy 331.75321 -249.32767)
				(xy 331.75321 -251.714254) (xy 331.899006 -251.86005)
			)
		)
	)
	(zone
		(layer "F.Cu")
		(hatch none 0.5)
		(connect_pads
			(clearance 0)
		)
		(min_thickness 0.25)
		(keepout
			(tracks allowed)
			(vias allowed)
			(pads allowed)
			(copperpour allowed)
			(footprints allowed)
		)
		(placement
			(enabled no)
			(sheetname "")
		)
		(fill
			(thermal_gap 0.5)
			(thermal_bridge_width 0.5)
			(island_removal_mode 0)
		)
		(polygon
			(pts
				(xy 41.29151 -214.96655) (xy 41.29151 -214.522812) (xy 43.616626 -214.522812) (xy 43.616626 -214.96655)
			)
		)
	)
	(zone
		(layer "F.Cu")
		(hatch none 0.5)
		(connect_pads
			(clearance 0)
		)
		(min_thickness 0.25)
		(keepout
			(tracks allowed)
			(vias allowed)
			(pads allowed)
			(copperpour allowed)
			(footprints allowed)
		)
		(placement
			(enabled no)
			(sheetname "")
		)
		(fill
			(thermal_gap 0.5)
			(thermal_bridge_width 0.5)
			(island_removal_mode 0)
		)
		(polygon
			(pts
				(xy 11.11631 -310.166512) (xy 11.11631 -309.722774) (xy 13.441426 -309.722774) (xy 13.441426 -310.166512)
			)
		)
	)
	(zone
		(layer "F.Cu")
		(hatch none 0.5)
		(connect_pads
			(clearance 0)
		)
		(min_thickness 0.25)
		(keepout
			(tracks allowed)
			(vias allowed)
			(pads allowed)
			(copperpour allowed)
			(footprints allowed)
		)
		(placement
			(enabled no)
			(sheetname "")
		)
		(fill
			(thermal_gap 0.5)
			(thermal_bridge_width 0.5)
			(island_removal_mode 0)
		)
		(polygon
			(pts
				(xy 169.491406 -351.527618) (xy 169.491406 -355.533198) (xy 169.971466 -356.013258) (xy 172.036486 -356.013258)
				(xy 172.308266 -355.741478) (xy 172.308266 -353.887278) (xy 172.559726 -353.635818) (xy 174.479966 -353.635818)
				(xy 174.896526 -353.219258) (xy 174.896526 -351.728278) (xy 174.248826 -351.080578) (xy 169.938446 -351.080578)
			)
		)
	)
	(zone
		(layer "F.Cu")
		(hatch none 0.5)
		(connect_pads
			(clearance 0)
		)
		(min_thickness 0.25)
		(keepout
			(tracks allowed)
			(vias allowed)
			(pads allowed)
			(copperpour allowed)
			(footprints allowed)
		)
		(placement
			(enabled no)
			(sheetname "")
		)
		(fill
			(thermal_gap 0.5)
			(thermal_bridge_width 0.5)
			(island_removal_mode 0)
		)
		(polygon
			(pts
				(xy 277.58771 -252.366526) (xy 277.58771 -251.922788) (xy 279.912826 -251.922788) (xy 279.912826 -252.366526)
			)
		)
	)
	(zone
		(layer "F.Cu")
		(hatch none 0.5)
		(connect_pads
			(clearance 0)
		)
		(min_thickness 0.25)
		(keepout
			(tracks allowed)
			(vias allowed)
			(pads allowed)
			(copperpour allowed)
			(footprints allowed)
		)
		(placement
			(enabled no)
			(sheetname "")
		)
		(fill
			(thermal_gap 0.5)
			(thermal_bridge_width 0.5)
			(island_removal_mode 0)
		)
		(polygon
			(pts
				(xy 415.307526 -235.2548) (xy 413.275526 -235.2548) (xy 413.097726 -235.2548) (xy 413.097726 -234.714288)
				(xy 415.798762 -234.714288) (xy 415.798762 -235.2548)
			)
		)
	)
	(zone
		(layer "F.Cu")
		(hatch none 0.5)
		(connect_pads
			(clearance 0)
		)
		(min_thickness 0.25)
		(keepout
			(tracks allowed)
			(vias allowed)
			(pads allowed)
			(copperpour allowed)
			(footprints allowed)
		)
		(placement
			(enabled no)
			(sheetname "")
		)
		(fill
			(thermal_gap 0.5)
			(thermal_bridge_width 0.5)
			(island_removal_mode 0)
		)
		(polygon
			(pts
				(xy 445.493902 -278.607012) (xy 443.461902 -278.607012) (xy 443.461902 -278.604726) (xy 443.283086 -278.604726)
				(xy 443.283086 -278.36749) (xy 443.145164 -278.36749) (xy 443.101984 -278.32431) (xy 443.101984 -278.191468)
				(xy 443.101984 -277.88743) (xy 443.174628 -277.814786) (xy 445.714882 -277.814786) (xy 445.856106 -277.95601)
				(xy 445.856106 -278.153114) (xy 445.774572 -278.234648) (xy 445.774572 -278.607012) (xy 445.677036 -278.607012)
				(xy 445.630046 -278.607012)
			)
		)
	)
	(zone
		(layer "F.Cu")
		(hatch none 0.5)
		(connect_pads
			(clearance 0)
		)
		(min_thickness 0.25)
		(keepout
			(tracks allowed)
			(vias allowed)
			(pads allowed)
			(copperpour allowed)
			(footprints allowed)
		)
		(placement
			(enabled no)
			(sheetname "")
		)
		(fill
			(thermal_gap 0.5)
			(thermal_bridge_width 0.5)
			(island_removal_mode 0)
		)
		(polygon
			(pts
				(xy 176.979326 -263.076436) (xy 179.011326 -263.076436) (xy 179.011326 -263.305036) (xy 176.979326 -263.305036)
				(xy 176.812702 -263.305036) (xy 176.715166 -263.305036) (xy 176.715166 -263.076436) (xy 176.812702 -263.076436)
			)
		)
	)
	(zone
		(layer "F.Cu")
		(hatch none 0.5)
		(connect_pads
			(clearance 0)
		)
		(min_thickness 0.25)
		(keepout
			(tracks not_allowed)
			(vias allowed)
			(pads allowed)
			(copperpour not_allowed)
			(footprints allowed)
		)
		(placement
			(enabled no)
			(sheetname "")
		)
		(fill
			(thermal_gap 0.5)
			(thermal_bridge_width 0.5)
			(island_removal_mode 0)
		)
		(polygon
			(pts
				(arc
					(start 92.53474 -297.515026)
					(mid 90.439748 -299.610018)
					(end 88.344756 -297.515026)
				)
				(arc
					(start 88.344756 -297.515026)
					(mid 90.439748 -295.420034)
					(end 92.53474 -297.515026)
				)
			)
		)
	)
	(zone
		(layer "F.Cu")
		(hatch none 0.5)
		(connect_pads
			(clearance 0)
		)
		(min_thickness 0.25)
		(keepout
			(tracks allowed)
			(vias allowed)
			(pads allowed)
			(copperpour allowed)
			(footprints allowed)
		)
		(placement
			(enabled no)
			(sheetname "")
		)
		(fill
			(thermal_gap 0.5)
			(thermal_bridge_width 0.5)
			(island_removal_mode 0)
		)
		(polygon
			(pts
				(xy 44.735242 -280.416508) (xy 44.735242 -279.97277) (xy 47.060358 -279.97277) (xy 47.060358 -280.416508)
			)
		)
	)
	(zone
		(layer "F.Cu")
		(hatch none 0.5)
		(connect_pads
			(clearance 0)
		)
		(min_thickness 0.25)
		(keepout
			(tracks not_allowed)
			(vias allowed)
			(pads allowed)
			(copperpour not_allowed)
			(footprints allowed)
		)
		(placement
			(enabled no)
			(sheetname "")
		)
		(fill
			(thermal_gap 0.5)
			(thermal_bridge_width 0.5)
			(island_removal_mode 0)
		)
		(polygon
			(pts
				(xy 439.368946 -11.992356) (xy 439.544206 -11.992356) (xy 439.572146 -11.964416) (xy 439.572146 -10.569956)
				(xy 439.549286 -10.547096) (xy 439.379106 -10.547096) (xy 439.358786 -10.567416) (xy 439.358786 -11.982196)
			)
		)
	)
	(zone
		(layer "F.Cu")
		(hatch none 0.5)
		(connect_pads
			(clearance 0)
		)
		(min_thickness 0.25)
		(keepout
			(tracks allowed)
			(vias allowed)
			(pads allowed)
			(copperpour allowed)
			(footprints allowed)
		)
		(placement
			(enabled no)
			(sheetname "")
		)
		(fill
			(thermal_gap 0.5)
			(thermal_bridge_width 0.5)
			(island_removal_mode 0)
		)
		(polygon
			(pts
				(xy 210.598258 -214.85479) (xy 210.598258 -214.62619) (xy 212.630258 -214.62619) (xy 212.630258 -214.85479)
			)
		)
	)
	(zone
		(layer "F.Cu")
		(hatch none 0.5)
		(connect_pads
			(clearance 0)
		)
		(min_thickness 0.25)
		(keepout
			(tracks allowed)
			(vias allowed)
			(pads allowed)
			(copperpour allowed)
			(footprints allowed)
		)
		(placement
			(enabled no)
			(sheetname "")
		)
		(fill
			(thermal_gap 0.5)
			(thermal_bridge_width 0.5)
			(island_removal_mode 0)
		)
		(polygon
			(pts
				(xy 403.545548 -20.04822) (xy 403.545548 -16.913606) (xy 405.32431 -16.913606) (xy 405.32431 -20.04822)
			)
		)
	)
	(zone
		(layer "F.Cu")
		(hatch none 0.5)
		(connect_pads
			(clearance 0)
		)
		(min_thickness 0.25)
		(keepout
			(tracks allowed)
			(vias allowed)
			(pads allowed)
			(copperpour allowed)
			(footprints allowed)
		)
		(placement
			(enabled no)
			(sheetname "")
		)
		(fill
			(thermal_gap 0.5)
			(thermal_bridge_width 0.5)
			(island_removal_mode 0)
		)
		(polygon
			(pts
				(xy 458.538326 -225.904806) (xy 458.538326 -225.676206) (xy 460.570326 -225.676206) (xy 460.570326 -225.904806)
			)
		)
	)
	(zone
		(layer "F.Cu")
		(hatch none 0.5)
		(connect_pads
			(clearance 0)
		)
		(min_thickness 0.25)
		(keepout
			(tracks allowed)
			(vias allowed)
			(pads allowed)
			(copperpour allowed)
			(footprints allowed)
		)
		(placement
			(enabled no)
			(sheetname "")
		)
		(fill
			(thermal_gap 0.5)
			(thermal_bridge_width 0.5)
			(island_removal_mode 0)
		)
		(polygon
			(pts
				(xy 119.698008 -404.802594) (xy 119.698008 -399.959576) (xy 121.582434 -399.959576) (xy 121.582434 -404.802594)
			)
		)
	)
	(zone
		(layer "F.Cu")
		(hatch none 0.5)
		(connect_pads
			(clearance 0)
		)
		(min_thickness 0.25)
		(keepout
			(tracks allowed)
			(vias allowed)
			(pads allowed)
			(copperpour allowed)
			(footprints allowed)
		)
		(placement
			(enabled no)
			(sheetname "")
		)
		(fill
			(thermal_gap 0.5)
			(thermal_bridge_width 0.5)
			(island_removal_mode 0)
		)
		(polygon
			(pts
				(xy 440.006994 -293.906956) (xy 442.038994 -293.906956) (xy 442.038994 -293.678356) (xy 440.006994 -293.678356)
				(xy 439.875676 -293.678356) (xy 439.849768 -293.678356) (xy 439.849768 -293.906956) (xy 439.875676 -293.906956)
			)
		)
	)
	(zone
		(layer "F.Cu")
		(hatch none 0.5)
		(connect_pads
			(clearance 0)
		)
		(min_thickness 0.25)
		(keepout
			(tracks allowed)
			(vias allowed)
			(pads allowed)
			(copperpour allowed)
			(footprints allowed)
		)
		(placement
			(enabled no)
			(sheetname "")
		)
		(fill
			(thermal_gap 0.5)
			(thermal_bridge_width 0.5)
			(island_removal_mode 0)
		)
		(polygon
			(pts
				(xy 289.231578 -216.666572) (xy 289.231578 -216.222834) (xy 291.556694 -216.222834) (xy 291.556694 -216.666572)
			)
		)
	)
	(zone
		(layer "F.Cu")
		(hatch none 0.5)
		(connect_pads
			(clearance 0)
		)
		(min_thickness 0.25)
		(keepout
			(tracks allowed)
			(vias allowed)
			(pads allowed)
			(copperpour allowed)
			(footprints allowed)
		)
		(placement
			(enabled no)
			(sheetname "")
		)
		(fill
			(thermal_gap 0.5)
			(thermal_bridge_width 0.5)
			(island_removal_mode 0)
		)
		(polygon
			(pts
				(xy 63.977012 -310.166512) (xy 63.977012 -309.722774) (xy 66.186812 -309.722774) (xy 66.186812 -310.166512)
			)
		)
	)
	(zone
		(layer "F.Cu")
		(hatch none 0.5)
		(connect_pads
			(clearance 0)
		)
		(min_thickness 0.25)
		(keepout
			(tracks allowed)
			(vias allowed)
			(pads allowed)
			(copperpour allowed)
			(footprints allowed)
		)
		(placement
			(enabled no)
			(sheetname "")
		)
		(fill
			(thermal_gap 0.5)
			(thermal_bridge_width 0.5)
			(island_removal_mode 0)
		)
		(polygon
			(pts
				(xy 180.423058 -286.254952) (xy 180.423058 -286.026352) (xy 182.455058 -286.026352) (xy 182.455058 -286.254952)
			)
		)
	)
	(zone
		(layer "F.Cu")
		(hatch none 0.5)
		(connect_pads
			(clearance 0)
		)
		(min_thickness 0.25)
		(keepout
			(tracks allowed)
			(vias allowed)
			(pads allowed)
			(copperpour allowed)
			(footprints allowed)
		)
		(placement
			(enabled no)
			(sheetname "")
		)
		(fill
			(thermal_gap 0.5)
			(thermal_bridge_width 0.5)
			(island_removal_mode 0)
		)
		(polygon
			(pts
				(xy 428.363126 -286.254952) (xy 428.363126 -286.026352) (xy 430.395126 -286.026352) (xy 430.395126 -286.254952)
			)
		)
	)
	(zone
		(layer "F.Cu")
		(hatch none 0.5)
		(connect_pads
			(clearance 0)
		)
		(min_thickness 0.25)
		(keepout
			(tracks allowed)
			(vias allowed)
			(pads allowed)
			(copperpour allowed)
			(footprints allowed)
		)
		(placement
			(enabled no)
			(sheetname "")
		)
		(fill
			(thermal_gap 0.5)
			(thermal_bridge_width 0.5)
			(island_removal_mode 0)
		)
		(polygon
			(pts
				(xy 292.67531 -314.41644) (xy 292.67531 -313.972702) (xy 295.000426 -313.972702) (xy 295.000426 -314.41644)
			)
		)
	)
	(zone
		(layer "F.Cu")
		(hatch none 0.5)
		(connect_pads
			(clearance 0)
		)
		(min_thickness 0.25)
		(keepout
			(tracks allowed)
			(vias allowed)
			(pads allowed)
			(copperpour allowed)
			(footprints allowed)
		)
		(placement
			(enabled no)
			(sheetname "")
		)
		(fill
			(thermal_gap 0.5)
			(thermal_bridge_width 0.5)
			(island_removal_mode 0)
		)
		(polygon
			(pts
				(xy 137.791952 -345.159838) (xy 136.044432 -345.159838) (xy 136.044432 -343.224358) (xy 137.791952 -343.224358)
			)
		)
	)
	(zone
		(layer "F.Cu")
		(hatch none 0.5)
		(connect_pads
			(clearance 0)
		)
		(min_thickness 0.25)
		(keepout
			(tracks allowed)
			(vias allowed)
			(pads allowed)
			(copperpour allowed)
			(footprints not_allowed)
		)
		(placement
			(enabled no)
			(sheetname "")
		)
		(fill
			(thermal_gap 0.5)
			(thermal_bridge_width 0.5)
			(island_removal_mode 0)
		)
		(polygon
			(pts
				(arc
					(start 231.650032 -192.499996)
					(mid 236.650022 -187.500006)
					(end 241.650012 -192.499996)
				)
				(arc
					(start 241.650012 -192.499996)
					(mid 236.650022 -197.499986)
					(end 231.650032 -192.499996)
				)
			)
		)
	)
	(zone
		(layer "F.Cu")
		(hatch none 0.5)
		(connect_pads
			(clearance 0)
		)
		(min_thickness 0.25)
		(keepout
			(tracks allowed)
			(vias allowed)
			(pads allowed)
			(copperpour allowed)
			(footprints allowed)
		)
		(placement
			(enabled no)
			(sheetname "")
		)
		(fill
			(thermal_gap 0.5)
			(thermal_bridge_width 0.5)
			(island_removal_mode 0)
		)
		(polygon
			(pts
				(xy 157.791658 -250.554998) (xy 157.791658 -250.326398) (xy 159.823658 -250.326398) (xy 159.823658 -250.554998)
			)
		)
	)
	(zone
		(layer "F.Cu")
		(hatch none 0.5)
		(connect_pads
			(clearance 0)
		)
		(min_thickness 0.25)
		(keepout
			(tracks allowed)
			(vias allowed)
			(pads allowed)
			(copperpour allowed)
			(footprints allowed)
		)
		(placement
			(enabled no)
			(sheetname "")
		)
		(fill
			(thermal_gap 0.5)
			(thermal_bridge_width 0.5)
			(island_removal_mode 0)
		)
		(polygon
			(pts
				(xy 138.32332 -284.193488) (xy 138.61034 -284.193488) (xy 138.64082 -284.163008) (xy 138.64082 -283.535628)
				(xy 138.55446 -283.449268) (xy 138.3665 -283.449268) (xy 138.29284 -283.522928) (xy 138.29284 -284.163008)
			)
		)
	)
	(zone
		(layer "F.Cu")
		(hatch none 0.5)
		(connect_pads
			(clearance 0)
		)
		(min_thickness 0.25)
		(keepout
			(tracks allowed)
			(vias allowed)
			(pads allowed)
			(copperpour allowed)
			(footprints allowed)
		)
		(placement
			(enabled no)
			(sheetname "")
		)
		(fill
			(thermal_gap 0.5)
			(thermal_bridge_width 0.5)
			(island_removal_mode 0)
		)
		(polygon
			(pts
				(xy 409.831794 -231.62641) (xy 411.863794 -231.62641) (xy 412.073344 -231.62641) (xy 412.073344 -232.186988)
				(xy 409.64866 -232.186988) (xy 409.64866 -231.85501) (xy 409.64866 -231.62641) (xy 409.69565 -231.62641)
			)
		)
	)
	(zone
		(layer "F.Cu")
		(hatch none 0.5)
		(connect_pads
			(clearance 0)
		)
		(min_thickness 0.25)
		(keepout
			(tracks allowed)
			(vias allowed)
			(pads allowed)
			(copperpour allowed)
			(footprints allowed)
		)
		(placement
			(enabled no)
			(sheetname "")
		)
		(fill
			(thermal_gap 0.5)
			(thermal_bridge_width 0.5)
			(island_removal_mode 0)
		)
		(polygon
			(pts
				(xy 311.89168 -292.316662) (xy 311.89168 -291.872924) (xy 313.94908 -291.872924) (xy 313.94908 -292.316662)
			)
		)
	)
	(zone
		(layer "F.Cu")
		(hatch none 0.5)
		(connect_pads
			(clearance 0)
		)
		(min_thickness 0.25)
		(keepout
			(tracks not_allowed)
			(vias allowed)
			(pads allowed)
			(copperpour not_allowed)
			(footprints allowed)
		)
		(placement
			(enabled no)
			(sheetname "")
		)
		(fill
			(thermal_gap 0.5)
			(thermal_bridge_width 0.5)
			(island_removal_mode 0)
		)
		(polygon
			(pts
				(arc
					(start 458.659992 -160.50006)
					(mid 461.460088 -157.699964)
					(end 464.25993 -160.50006)
				)
				(arc
					(start 464.25993 -160.50006)
					(mid 461.460088 -163.299902)
					(end 458.659992 -160.50006)
				)
			)
		)
	)
	(zone
		(layer "F.Cu")
		(hatch none 0.5)
		(connect_pads
			(clearance 0)
		)
		(min_thickness 0.25)
		(keepout
			(tracks allowed)
			(vias allowed)
			(pads allowed)
			(copperpour allowed)
			(footprints not_allowed)
		)
		(placement
			(enabled no)
			(sheetname "")
		)
		(fill
			(thermal_gap 0.5)
			(thermal_bridge_width 0.5)
			(island_removal_mode 0)
		)
		(polygon
			(pts
				(arc
					(start 68.13296 -47.049944)
					(mid 70.383146 -44.799758)
					(end 72.633078 -47.049944)
				)
				(arc
					(start 72.633078 -47.049944)
					(mid 70.383146 -49.299876)
					(end 68.13296 -47.049944)
				)
			)
		)
	)
	(zone
		(layer "F.Cu")
		(hatch none 0.5)
		(connect_pads
			(clearance 0)
		)
		(min_thickness 0.25)
		(keepout
			(tracks allowed)
			(vias allowed)
			(pads allowed)
			(copperpour allowed)
			(footprints allowed)
		)
		(placement
			(enabled no)
			(sheetname "")
		)
		(fill
			(thermal_gap 0.5)
			(thermal_bridge_width 0.5)
			(island_removal_mode 0)
		)
		(polygon
			(pts
				(xy 443.450726 -248.854976) (xy 443.450726 -248.626376) (xy 445.482726 -248.626376) (xy 445.482726 -248.854976)
			)
		)
	)
	(zone
		(layer "F.Cu")
		(hatch none 0.5)
		(connect_pads
			(clearance 0)
		)
		(min_thickness 0.25)
		(keepout
			(tracks allowed)
			(vias allowed)
			(pads allowed)
			(copperpour allowed)
			(footprints not_allowed)
		)
		(placement
			(enabled no)
			(sheetname "")
		)
		(fill
			(thermal_gap 0.5)
			(thermal_bridge_width 0.5)
			(island_removal_mode 0)
		)
		(polygon
			(pts
				(arc
					(start 84.583016 -59.04992)
					(mid 93.58315 -62.050016)
					(end 102.583234 -59.04992)
				)
				(arc
					(start 104.58323 -59.04992)
					(mid 113.583212 -62.049914)
					(end 122.583194 -59.04992)
				)
				(arc
					(start 122.583194 -59.04992)
					(mid 126.839769 -61.280165)
					(end 131.583176 -62.049914)
				)
				(arc
					(start 131.583176 -62.049914)
					(mid 134.647805 -61.733511)
					(end 137.583164 -60.797694)
				)
				(arc
					(start 137.583164 -60.797694)
					(mid 145.319147 -61.949166)
					(end 152.583134 -59.04992)
				)
				(xy 168.283128 -59.04992) (xy 168.283128 -35.049968)
				(arc
					(start 152.583134 -35.049968)
					(mid 145.319142 -32.150768)
					(end 137.583164 -33.302194)
				)
				(arc
					(start 137.583164 -33.302194)
					(mid 134.647814 -32.366331)
					(end 131.583176 -32.049974)
				)
				(arc
					(start 131.583176 -32.049974)
					(mid 126.839769 -32.819723)
					(end 122.583194 -35.049968)
				)
				(arc
					(start 122.583194 -35.049968)
					(mid 113.583212 -32.049974)
					(end 104.58323 -35.049968)
				)
				(arc
					(start 102.583234 -35.049968)
					(mid 93.58315 -32.050025)
					(end 84.583016 -35.049968)
				)
				(arc
					(start 72.58304 -35.049968)
					(mid 58.741159 -32.852933)
					(end 49.126394 -43.049952)
				)
				(xy 40.583104 -43.049952) (xy 40.583104 -51.049936)
				(arc
					(start 49.126394 -51.049936)
					(mid 58.741202 -61.246827)
					(end 72.58304 -59.04992)
				)
			)
		)
	)
	(zone
		(layer "F.Cu")
		(hatch none 0.5)
		(connect_pads
			(clearance 0)
		)
		(min_thickness 0.25)
		(keepout
			(tracks allowed)
			(vias allowed)
			(pads allowed)
			(copperpour allowed)
			(footprints allowed)
		)
		(placement
			(enabled no)
			(sheetname "")
		)
		(fill
			(thermal_gap 0.5)
			(thermal_bridge_width 0.5)
			(island_removal_mode 0)
		)
		(polygon
			(pts
				(xy 304.319178 -197.966584) (xy 304.319178 -197.522846) (xy 306.644294 -197.522846) (xy 306.644294 -197.966584)
			)
		)
	)
	(zone
		(layer "F.Cu")
		(hatch none 0.5)
		(connect_pads
			(clearance 0)
		)
		(min_thickness 0.25)
		(keepout
			(tracks allowed)
			(vias allowed)
			(pads allowed)
			(copperpour allowed)
			(footprints allowed)
		)
		(placement
			(enabled no)
			(sheetname "")
		)
		(fill
			(thermal_gap 0.5)
			(thermal_bridge_width 0.5)
			(island_removal_mode 0)
		)
		(polygon
			(pts
				(xy 14.560042 -289.766502) (xy 14.560042 -289.322764) (xy 16.885158 -289.322764) (xy 16.885158 -289.766502)
			)
		)
	)
	(zone
		(layer "F.Cu")
		(hatch none 0.5)
		(connect_pads
			(clearance 0)
		)
		(min_thickness 0.25)
		(keepout
			(tracks allowed)
			(vias allowed)
			(pads allowed)
			(copperpour allowed)
			(footprints allowed)
		)
		(placement
			(enabled no)
			(sheetname "")
		)
		(fill
			(thermal_gap 0.5)
			(thermal_bridge_width 0.5)
			(island_removal_mode 0)
		)
		(polygon
			(pts
				(xy 55.70728 -146.957288) (xy 55.70728 -145.141188) (xy 57.0865 -145.141188) (xy 57.0865 -146.957288)
			)
		)
	)
	(zone
		(layer "F.Cu")
		(hatch none 0.5)
		(connect_pads
			(clearance 0)
		)
		(min_thickness 0.25)
		(keepout
			(tracks allowed)
			(vias allowed)
			(pads allowed)
			(copperpour allowed)
			(footprints allowed)
		)
		(placement
			(enabled no)
			(sheetname "")
		)
		(fill
			(thermal_gap 0.5)
			(thermal_bridge_width 0.5)
			(island_removal_mode 0)
		)
		(polygon
			(pts
				(xy 311.91708 -267.66647) (xy 311.91708 -267.222732) (xy 314.10148 -267.222732) (xy 314.10148 -267.66647)
			)
		)
	)
	(zone
		(layer "F.Cu")
		(hatch none 0.5)
		(connect_pads
			(clearance 0)
		)
		(min_thickness 0.25)
		(keepout
			(tracks allowed)
			(vias allowed)
			(pads allowed)
			(copperpour allowed)
			(footprints allowed)
		)
		(placement
			(enabled no)
			(sheetname "")
		)
		(fill
			(thermal_gap 0.5)
			(thermal_bridge_width 0.5)
			(island_removal_mode 0)
		)
		(polygon
			(pts
				(xy 258.858766 -269.993364) (xy 265.125962 -269.993364) (xy 265.285474 -269.833852) (xy 265.285474 -268.569694)
				(xy 265.13917 -268.42339) (xy 259.03174 -268.42339) (xy 258.858766 -268.596364)
			)
		)
	)
	(zone
		(layer "F.Cu")
		(hatch none 0.5)
		(connect_pads
			(clearance 0)
		)
		(min_thickness 0.25)
		(keepout
			(tracks allowed)
			(vias allowed)
			(pads allowed)
			(copperpour allowed)
			(footprints allowed)
		)
		(placement
			(enabled no)
			(sheetname "")
		)
		(fill
			(thermal_gap 0.5)
			(thermal_bridge_width 0.5)
			(island_removal_mode 0)
		)
		(polygon
			(pts
				(xy 289.231578 -300.816518) (xy 289.231578 -300.37278) (xy 291.556694 -300.37278) (xy 291.556694 -300.816518)
			)
		)
	)
	(zone
		(layer "F.Cu")
		(hatch none 0.5)
		(connect_pads
			(clearance 0)
		)
		(min_thickness 0.25)
		(keepout
			(tracks allowed)
			(vias allowed)
			(pads allowed)
			(copperpour allowed)
			(footprints allowed)
		)
		(placement
			(enabled no)
			(sheetname "")
		)
		(fill
			(thermal_gap 0.5)
			(thermal_bridge_width 0.5)
			(island_removal_mode 0)
		)
		(polygon
			(pts
				(xy 161.891726 -240.976404) (xy 163.923726 -240.976404) (xy 164.038534 -240.976404) (xy 164.038534 -241.678968)
				(xy 161.68497 -241.678968) (xy 161.68497 -240.976404)
			)
		)
	)
	(zone
		(layer "F.Cu")
		(hatch none 0.5)
		(connect_pads
			(clearance 0)
		)
		(min_thickness 0.25)
		(keepout
			(tracks allowed)
			(vias allowed)
			(pads allowed)
			(copperpour allowed)
			(footprints allowed)
		)
		(placement
			(enabled no)
			(sheetname "")
		)
		(fill
			(thermal_gap 0.5)
			(thermal_bridge_width 0.5)
			(island_removal_mode 0)
		)
		(polygon
			(pts
				(xy 161.891726 -235.0262) (xy 163.923726 -235.0262) (xy 164.236908 -235.0262) (xy 164.236908 -235.711238)
				(xy 161.453576 -235.711238) (xy 161.453576 -235.0262)
			)
		)
	)
	(zone
		(layer "F.Cu")
		(hatch none 0.5)
		(connect_pads
			(clearance 0)
		)
		(min_thickness 0.25)
		(keepout
			(tracks allowed)
			(vias allowed)
			(pads allowed)
			(copperpour allowed)
			(footprints allowed)
		)
		(placement
			(enabled no)
			(sheetname "")
		)
		(fill
			(thermal_gap 0.5)
			(thermal_bridge_width 0.5)
			(island_removal_mode 0)
		)
		(polygon
			(pts
				(xy 458.538326 -310.055006) (xy 458.538326 -309.826406) (xy 460.570326 -309.826406) (xy 460.570326 -310.055006)
			)
		)
	)
	(zone
		(layer "F.Cu")
		(hatch none 0.5)
		(connect_pads
			(clearance 0)
		)
		(min_thickness 0.25)
		(keepout
			(tracks allowed)
			(vias allowed)
			(pads allowed)
			(copperpour allowed)
			(footprints allowed)
		)
		(placement
			(enabled no)
			(sheetname "")
		)
		(fill
			(thermal_gap 0.5)
			(thermal_bridge_width 0.5)
			(island_removal_mode 0)
		)
		(polygon
			(pts
				(xy 405.25954 -164.262308) (xy 405.25954 -160.165288) (xy 407.20264 -160.165288) (xy 407.20264 -164.262308)
			)
		)
	)
	(zone
		(layer "F.Cu")
		(hatch none 0.5)
		(connect_pads
			(clearance 0)
		)
		(min_thickness 0.25)
		(keepout
			(tracks allowed)
			(vias allowed)
			(pads allowed)
			(copperpour allowed)
			(footprints allowed)
		)
		(placement
			(enabled no)
			(sheetname "")
		)
		(fill
			(thermal_gap 0.5)
			(thermal_bridge_width 0.5)
			(island_removal_mode 0)
		)
		(polygon
			(pts
				(xy 276.469094 -276.16658) (xy 274.143978 -276.16658) (xy 274.014184 -276.16658) (xy 274.014184 -274.963636)
				(xy 276.53488 -274.963636) (xy 276.53488 -276.16658)
			)
		)
	)
	(zone
		(layer "F.Cu")
		(hatch none 0.5)
		(connect_pads
			(clearance 0)
		)
		(min_thickness 0.25)
		(keepout
			(tracks allowed)
			(vias allowed)
			(pads allowed)
			(copperpour allowed)
			(footprints allowed)
		)
		(placement
			(enabled no)
			(sheetname "")
		)
		(fill
			(thermal_gap 0.5)
			(thermal_bridge_width 0.5)
			(island_removal_mode 0)
		)
		(polygon
			(pts
				(xy 55.0291 -159.116268) (xy 55.0291 -155.580588) (xy 57.1119 -155.580588) (xy 57.1119 -159.116268)
			)
		)
	)
	(zone
		(layer "F.Cu")
		(hatch none 0.5)
		(connect_pads
			(clearance 0)
		)
		(min_thickness 0.25)
		(keepout
			(tracks allowed)
			(vias allowed)
			(pads allowed)
			(copperpour allowed)
			(footprints allowed)
		)
		(placement
			(enabled no)
			(sheetname "")
		)
		(fill
			(thermal_gap 0.5)
			(thermal_bridge_width 0.5)
			(island_removal_mode 0)
		)
		(polygon
			(pts
				(xy 335.93532 -216.906348) (xy 336.22234 -216.906348) (xy 336.25282 -216.875868) (xy 336.25282 -216.248488)
				(xy 336.16646 -216.162128) (xy 335.9785 -216.162128) (xy 335.90484 -216.235788) (xy 335.90484 -216.875868)
			)
		)
	)
	(zone
		(layer "F.Cu")
		(hatch none 0.5)
		(connect_pads
			(clearance 0)
		)
		(min_thickness 0.25)
		(keepout
			(tracks allowed)
			(vias allowed)
			(pads allowed)
			(copperpour allowed)
			(footprints allowed)
		)
		(placement
			(enabled no)
			(sheetname "")
		)
		(fill
			(thermal_gap 0.5)
			(thermal_bridge_width 0.5)
			(island_removal_mode 0)
		)
		(polygon
			(pts
				(xy 440.006994 -260.754876) (xy 440.006994 -260.526276) (xy 442.038994 -260.526276) (xy 442.038994 -260.754876)
			)
		)
	)
	(zone
		(layer "F.Cu")
		(hatch none 0.5)
		(connect_pads
			(clearance 0)
		)
		(min_thickness 0.25)
		(keepout
			(tracks allowed)
			(vias allowed)
			(pads allowed)
			(copperpour allowed)
			(footprints allowed)
		)
		(placement
			(enabled no)
			(sheetname "")
		)
		(fill
			(thermal_gap 0.5)
			(thermal_bridge_width 0.5)
			(island_removal_mode 0)
		)
		(polygon
			(pts
				(xy 292.67531 -289.766502) (xy 292.67531 -289.322764) (xy 295.000426 -289.322764) (xy 295.000426 -289.766502)
			)
		)
	)
	(zone
		(layer "F.Cu")
		(hatch none 0.5)
		(connect_pads
			(clearance 0)
		)
		(min_thickness 0.25)
		(keepout
			(tracks allowed)
			(vias allowed)
			(pads allowed)
			(copperpour allowed)
			(footprints allowed)
		)
		(placement
			(enabled no)
			(sheetname "")
		)
		(fill
			(thermal_gap 0.5)
			(thermal_bridge_width 0.5)
			(island_removal_mode 0)
		)
		(polygon
			(pts
				(xy 41.29151 -210.716622) (xy 41.29151 -210.272884) (xy 43.616626 -210.272884) (xy 43.616626 -210.716622)
			)
		)
	)
	(zone
		(layer "F.Cu")
		(hatch none 0.5)
		(connect_pads
			(clearance 0)
		)
		(min_thickness 0.25)
		(keepout
			(tracks allowed)
			(vias allowed)
			(pads allowed)
			(copperpour allowed)
			(footprints allowed)
		)
		(placement
			(enabled no)
			(sheetname "")
		)
		(fill
			(thermal_gap 0.5)
			(thermal_bridge_width 0.5)
			(island_removal_mode 0)
		)
		(polygon
			(pts
				(xy 11.11631 -294.866568) (xy 11.11631 -294.42283) (xy 13.441426 -294.42283) (xy 13.441426 -294.866568)
			)
		)
	)
	(zone
		(layer "F.Cu")
		(hatch none 0.5)
		(connect_pads
			(clearance 0)
		)
		(min_thickness 0.25)
		(keepout
			(tracks allowed)
			(vias allowed)
			(pads allowed)
			(copperpour allowed)
			(footprints allowed)
		)
		(placement
			(enabled no)
			(sheetname "")
		)
		(fill
			(thermal_gap 0.5)
			(thermal_bridge_width 0.5)
			(island_removal_mode 0)
		)
		(polygon
			(pts
				(xy 176.979326 -275.82622) (xy 179.011326 -275.82622) (xy 179.011326 -276.05482) (xy 176.979326 -276.05482)
				(xy 176.848008 -276.05482) (xy 176.8221 -276.05482) (xy 176.8221 -275.82622) (xy 176.848008 -275.82622)
			)
		)
	)
	(zone
		(layer "F.Cu")
		(hatch none 0.5)
		(connect_pads
			(clearance 0)
		)
		(min_thickness 0.25)
		(keepout
			(tracks allowed)
			(vias allowed)
			(pads allowed)
			(copperpour allowed)
			(footprints allowed)
		)
		(placement
			(enabled no)
			(sheetname "")
		)
		(fill
			(thermal_gap 0.5)
			(thermal_bridge_width 0.5)
			(island_removal_mode 0)
		)
		(polygon
			(pts
				(xy 140.979144 -245.166388) (xy 140.801344 -245.344188) (xy 140.397738 -245.344442) (xy 140.397738 -246.68226)
				(xy 140.43152 -246.716042) (xy 140.80617 -246.716042) (xy 140.846048 -246.75592) (xy 140.846048 -247.090946)
				(xy 140.794486 -247.142508) (xy 140.794486 -247.334786) (xy 141.659102 -248.199402) (xy 141.659102 -248.423684)
				(xy 141.657324 -248.425462) (xy 141.792198 -248.560336) (xy 141.792198 -248.675144) (xy 140.223494 -250.243848)
				(xy 138.895074 -250.243848) (xy 138.86307 -250.275852) (xy 138.86307 -250.432316) (xy 138.607038 -250.688348)
				(xy 137.242804 -250.688348) (xy 137.19937 -250.731782) (xy 137.19937 -251.022358) (xy 138.49223 -251.022358)
				(xy 138.61923 -250.895358) (xy 141.89583 -250.895104) (xy 142.81023 -249.980704) (xy 142.81023 -249.966988)
				(xy 144.765522 -249.966988) (xy 144.994122 -249.738388) (xy 146.594322 -249.738388) (xy 146.691858 -249.738388)
				(xy 147.263866 -249.16638) (xy 147.54733 -249.16638) (xy 147.817078 -248.896632) (xy 148.216366 -248.896632)
				(xy 148.321522 -249.001788) (xy 148.429726 -249.109992) (xy 148.561298 -249.109992) (xy 148.769578 -248.901712)
				(xy 148.769578 -248.637552) (xy 148.627338 -248.495312) (xy 148.627338 -247.857772) (xy 148.571458 -247.801892)
				(xy 147.451318 -247.801892) (xy 147.448778 -247.804432) (xy 147.296378 -247.804432) (xy 147.020534 -247.528588)
				(xy 146.899122 -247.528588) (xy 146.818858 -247.528588) (xy 145.980658 -246.690388) (xy 145.857722 -246.690388)
				(xy 145.749518 -246.690388) (xy 145.392648 -246.333518) (xy 145.119598 -246.333518) (xy 144.863058 -246.076978)
				(xy 144.863058 -246.018812) (xy 144.807178 -245.962932) (xy 144.788128 -245.962932) (xy 144.231868 -245.406672)
				(xy 144.231868 -245.293388) (xy 144.231868 -245.250462) (xy 144.024858 -245.043452) (xy 143.981932 -245.043452)
				(xy 141.10208 -245.043452)
			)
		)
	)
	(zone
		(layer "F.Cu")
		(hatch none 0.5)
		(connect_pads
			(clearance 0)
		)
		(min_thickness 0.25)
		(keepout
			(tracks allowed)
			(vias allowed)
			(pads allowed)
			(copperpour allowed)
			(footprints allowed)
		)
		(placement
			(enabled no)
			(sheetname "")
		)
		(fill
			(thermal_gap 0.5)
			(thermal_bridge_width 0.5)
			(island_removal_mode 0)
		)
		(polygon
			(pts
				(xy 333.8576 -328.587608) (xy 333.8576 -330.279248) (xy 333.9211 -330.342748) (xy 342.63076 -330.342748)
				(xy 343.1159 -329.857608) (xy 343.1159 -328.188828) (xy 343.27338 -328.031348) (xy 371.2845 -328.031348)
				(xy 374.61698 -331.363828) (xy 379.2982 -331.363828) (xy 380.39548 -332.461108) (xy 380.39548 -334.709008)
				(xy 381.86106 -336.174588) (xy 387.88086 -336.174588) (xy 388.32536 -335.730088) (xy 388.32536 -335.265268)
				(xy 387.8834 -334.823308) (xy 384.2766 -334.823308) (xy 381.70358 -332.250288) (xy 381.70358 -330.711048)
				(xy 380.39548 -329.402948) (xy 376.682 -329.402948) (xy 373.41302 -326.133968) (xy 341.8586 -326.133968)
				(xy 339.89772 -328.094848) (xy 334.35036 -328.094848)
			)
		)
	)
	(zone
		(layer "F.Cu")
		(hatch none 0.5)
		(connect_pads
			(clearance 0)
		)
		(min_thickness 0.25)
		(keepout
			(tracks not_allowed)
			(vias allowed)
			(pads allowed)
			(copperpour not_allowed)
			(footprints allowed)
		)
		(placement
			(enabled no)
			(sheetname "")
		)
		(fill
			(thermal_gap 0.5)
			(thermal_bridge_width 0.5)
			(island_removal_mode 0)
		)
		(polygon
			(pts
				(xy 383.695702 -345.461336) (xy 387.63448 -345.461336) (xy 387.63448 -345.408504) (xy 387.5024 -345.276424)
				(xy 386.083556 -345.276424) (xy 386.083556 -343.117424) (xy 388.24027 -343.117424) (xy 388.24027 -342.867742)
				(xy 385.89966 -342.867742) (xy 385.89966 -343.190068) (xy 385.792218 -343.190068) (xy 385.792218 -345.220798)
				(xy 383.938018 -345.220798) (xy 383.938018 -344.979752) (xy 383.695702 -344.979752)
			)
		)
	)
	(zone
		(layer "F.Cu")
		(hatch none 0.5)
		(connect_pads
			(clearance 0)
		)
		(min_thickness 0.25)
		(keepout
			(tracks allowed)
			(vias allowed)
			(pads allowed)
			(copperpour allowed)
			(footprints allowed)
		)
		(placement
			(enabled no)
			(sheetname "")
		)
		(fill
			(thermal_gap 0.5)
			(thermal_bridge_width 0.5)
			(island_removal_mode 0)
		)
		(polygon
			(pts
				(xy 14.560042 -250.666504) (xy 14.560042 -250.222766) (xy 16.885158 -250.222766) (xy 16.885158 -250.666504)
			)
		)
	)
	(zone
		(layer "F.Cu")
		(hatch none 0.5)
		(connect_pads
			(clearance 0)
		)
		(min_thickness 0.25)
		(keepout
			(tracks allowed)
			(vias allowed)
			(pads allowed)
			(copperpour allowed)
			(footprints allowed)
		)
		(placement
			(enabled no)
			(sheetname "")
		)
		(fill
			(thermal_gap 0.5)
			(thermal_bridge_width 0.5)
			(island_removal_mode 0)
		)
		(polygon
			(pts
				(xy 14.560042 -234.516422) (xy 14.560042 -234.072684) (xy 16.885158 -234.072684) (xy 16.885158 -234.516422)
			)
		)
	)
	(zone
		(layer "F.Cu")
		(hatch none 0.5)
		(connect_pads
			(clearance 0)
		)
		(min_thickness 0.25)
		(keepout
			(tracks allowed)
			(vias allowed)
			(pads allowed)
			(copperpour allowed)
			(footprints allowed)
		)
		(placement
			(enabled no)
			(sheetname "")
		)
		(fill
			(thermal_gap 0.5)
			(thermal_bridge_width 0.5)
			(island_removal_mode 0)
		)
		(polygon
			(pts
				(xy 259.056378 -252.366526) (xy 259.056378 -251.922788) (xy 261.381494 -251.922788) (xy 261.381494 -252.366526)
				(xy 261.381494 -252.898656) (xy 259.056378 -252.898656)
			)
		)
	)
	(zone
		(layer "F.Cu")
		(hatch none 0.5)
		(connect_pads
			(clearance 0)
		)
		(min_thickness 0.25)
		(keepout
			(tracks allowed)
			(vias allowed)
			(pads allowed)
			(copperpour allowed)
			(footprints allowed)
		)
		(placement
			(enabled no)
			(sheetname "")
		)
		(fill
			(thermal_gap 0.5)
			(thermal_bridge_width 0.5)
			(island_removal_mode 0)
		)
		(polygon
			(pts
				(xy 405.788622 -309.204868) (xy 405.788622 -308.976268) (xy 407.719022 -308.976268) (xy 407.719022 -309.204868)
			)
		)
	)
	(zone
		(layer "F.Cu")
		(hatch none 0.5)
		(connect_pads
			(clearance 0)
		)
		(min_thickness 0.25)
		(keepout
			(tracks allowed)
			(vias allowed)
			(pads allowed)
			(copperpour allowed)
			(footprints allowed)
		)
		(placement
			(enabled no)
			(sheetname "")
		)
		(fill
			(thermal_gap 0.5)
			(thermal_bridge_width 0.5)
			(island_removal_mode 0)
		)
		(polygon
			(pts
				(xy 405.731726 -289.654996) (xy 405.731726 -289.426396) (xy 407.763726 -289.426396) (xy 407.763726 -289.654996)
			)
		)
	)
	(zone
		(layer "F.Cu")
		(hatch none 0.5)
		(connect_pads
			(clearance 0)
		)
		(min_thickness 0.25)
		(keepout
			(tracks allowed)
			(vias allowed)
			(pads allowed)
			(copperpour allowed)
			(footprints allowed)
		)
		(placement
			(enabled no)
			(sheetname "")
		)
		(fill
			(thermal_gap 0.5)
			(thermal_bridge_width 0.5)
			(island_removal_mode 0)
		)
		(polygon
			(pts
				(xy 307.76291 -203.916534) (xy 307.76291 -203.472796) (xy 310.088026 -203.472796) (xy 310.088026 -203.916534)
			)
		)
	)
	(zone
		(layer "F.Cu")
		(hatch none 0.5)
		(connect_pads
			(clearance 0)
		)
		(min_thickness 0.25)
		(keepout
			(tracks allowed)
			(vias allowed)
			(pads allowed)
			(copperpour allowed)
			(footprints allowed)
		)
		(placement
			(enabled no)
			(sheetname "")
		)
		(fill
			(thermal_gap 0.5)
			(thermal_bridge_width 0.5)
			(island_removal_mode 0)
		)
		(polygon
			(pts
				(xy 86.67242 -285.725108) (xy 86.95944 -285.725108) (xy 86.98992 -285.694628) (xy 86.98992 -285.067248)
				(xy 86.90356 -284.980888) (xy 86.7156 -284.980888) (xy 86.64194 -285.054548) (xy 86.64194 -285.694628)
			)
		)
	)
	(zone
		(layer "F.Cu")
		(hatch none 0.5)
		(connect_pads
			(clearance 0)
		)
		(min_thickness 0.25)
		(keepout
			(tracks allowed)
			(vias allowed)
			(pads allowed)
			(copperpour allowed)
			(footprints allowed)
		)
		(placement
			(enabled no)
			(sheetname "")
		)
		(fill
			(thermal_gap 0.5)
			(thermal_bridge_width 0.5)
			(island_removal_mode 0)
		)
		(polygon
			(pts
				(xy 210.598258 -280.305002) (xy 210.598258 -280.076402) (xy 212.630258 -280.076402) (xy 212.630258 -280.305002)
			)
		)
	)
	(zone
		(layer "F.Cu")
		(hatch none 0.5)
		(connect_pads
			(clearance 0)
		)
		(min_thickness 0.25)
		(keepout
			(tracks allowed)
			(vias allowed)
			(pads allowed)
			(copperpour allowed)
			(footprints allowed)
		)
		(placement
			(enabled no)
			(sheetname "")
		)
		(fill
			(thermal_gap 0.5)
			(thermal_bridge_width 0.5)
			(island_removal_mode 0)
		)
		(polygon
			(pts
				(xy 210.598258 -301.554896) (xy 210.598258 -301.326296) (xy 212.630258 -301.326296) (xy 212.630258 -301.554896)
			)
		)
	)
	(zone
		(layer "F.Cu")
		(hatch none 0.5)
		(connect_pads
			(clearance 0)
		)
		(min_thickness 0.25)
		(keepout
			(tracks allowed)
			(vias allowed)
			(pads allowed)
			(copperpour allowed)
			(footprints allowed)
		)
		(placement
			(enabled no)
			(sheetname "")
		)
		(fill
			(thermal_gap 0.5)
			(thermal_bridge_width 0.5)
			(island_removal_mode 0)
		)
		(polygon
			(pts
				(xy 304.319178 -228.566472) (xy 304.319178 -228.122734) (xy 306.644294 -228.122734) (xy 306.644294 -228.566472)
			)
		)
	)
	(zone
		(layer "F.Cu")
		(hatch none 0.5)
		(connect_pads
			(clearance 0)
		)
		(min_thickness 0.25)
		(keepout
			(tracks allowed)
			(vias allowed)
			(pads allowed)
			(copperpour allowed)
			(footprints allowed)
		)
		(placement
			(enabled no)
			(sheetname "")
		)
		(fill
			(thermal_gap 0.5)
			(thermal_bridge_width 0.5)
			(island_removal_mode 0)
		)
		(polygon
			(pts
				(xy 274.143978 -310.166512) (xy 274.143978 -309.722774) (xy 276.469094 -309.722774) (xy 276.469094 -310.166512)
			)
		)
	)
	(zone
		(layer "F.Cu")
		(hatch none 0.5)
		(connect_pads
			(clearance 0)
		)
		(min_thickness 0.25)
		(keepout
			(tracks not_allowed)
			(vias allowed)
			(pads allowed)
			(copperpour not_allowed)
			(footprints allowed)
		)
		(placement
			(enabled no)
			(sheetname "")
		)
		(fill
			(thermal_gap 0.5)
			(thermal_bridge_width 0.5)
			(island_removal_mode 0)
		)
		(polygon
			(pts
				(arc
					(start 98.1329 -47.049944)
					(mid 100.383086 -44.799758)
					(end 102.633018 -47.049944)
				)
				(arc
					(start 102.633018 -47.049944)
					(mid 100.383086 -49.299876)
					(end 98.1329 -47.049944)
				)
			)
		)
	)
	(zone
		(layer "F.Cu")
		(hatch none 0.5)
		(connect_pads
			(clearance 0)
		)
		(min_thickness 0.25)
		(keepout
			(tracks allowed)
			(vias allowed)
			(pads allowed)
			(copperpour allowed)
			(footprints allowed)
		)
		(placement
			(enabled no)
			(sheetname "")
		)
		(fill
			(thermal_gap 0.5)
			(thermal_bridge_width 0.5)
			(island_removal_mode 0)
		)
		(polygon
			(pts
				(xy 334.99298 -218.504008) (xy 335.28 -218.504008) (xy 335.31048 -218.473528) (xy 335.31048 -217.846148)
				(xy 335.22412 -217.759788) (xy 335.03616 -217.759788) (xy 334.9625 -217.833448) (xy 334.9625 -218.473528)
			)
		)
	)
	(zone
		(layer "F.Cu")
		(hatch none 0.5)
		(connect_pads
			(clearance 0)
		)
		(min_thickness 0.25)
		(keepout
			(tracks allowed)
			(vias allowed)
			(pads allowed)
			(copperpour allowed)
			(footprints allowed)
		)
		(placement
			(enabled no)
			(sheetname "")
		)
		(fill
			(thermal_gap 0.5)
			(thermal_bridge_width 0.5)
			(island_removal_mode 0)
		)
		(polygon
			(pts
				(xy 289.231578 -295.716452) (xy 289.231578 -295.272714) (xy 291.556694 -295.272714) (xy 291.556694 -295.716452)
			)
		)
	)
	(zone
		(layer "F.Cu")
		(hatch none 0.5)
		(connect_pads
			(clearance 0)
		)
		(min_thickness 0.25)
		(keepout
			(tracks allowed)
			(vias allowed)
			(pads allowed)
			(copperpour allowed)
			(footprints allowed)
		)
		(placement
			(enabled no)
			(sheetname "")
		)
		(fill
			(thermal_gap 0.5)
			(thermal_bridge_width 0.5)
			(island_removal_mode 0)
		)
		(polygon
			(pts
				(xy 176.979326 -249.47626) (xy 179.011326 -249.47626) (xy 179.011326 -249.70486) (xy 176.979326 -249.70486)
				(xy 176.812702 -249.70486) (xy 176.812702 -249.47626)
			)
		)
	)
	(zone
		(layer "F.Cu")
		(hatch none 0.5)
		(connect_pads
			(clearance 0)
		)
		(min_thickness 0.25)
		(keepout
			(tracks allowed)
			(vias allowed)
			(pads allowed)
			(copperpour allowed)
			(footprints allowed)
		)
		(placement
			(enabled no)
			(sheetname "")
		)
		(fill
			(thermal_gap 0.5)
			(thermal_bridge_width 0.5)
			(island_removal_mode 0)
		)
		(polygon
			(pts
				(xy 413.275526 -250.554998) (xy 413.275526 -250.326398) (xy 415.307526 -250.326398) (xy 415.307526 -250.554998)
			)
		)
	)
	(zone
		(layer "F.Cu")
		(hatch none 0.5)
		(connect_pads
			(clearance 0)
		)
		(min_thickness 0.25)
		(keepout
			(tracks allowed)
			(vias allowed)
			(pads allowed)
			(copperpour allowed)
			(footprints not_allowed)
		)
		(placement
			(enabled no)
			(sheetname "")
		)
		(fill
			(thermal_gap 0.5)
			(thermal_bridge_width 0.5)
			(island_removal_mode 0)
		)
		(polygon
			(pts
				(xy 116.225066 -237.00994) (xy 116.225066 -261.62) (xy 119.85498 -261.62) (xy 119.85498 -237.00994)
			)
		)
	)
	(zone
		(layer "F.Cu")
		(hatch none 0.5)
		(connect_pads
			(clearance 0)
		)
		(min_thickness 0.25)
		(keepout
			(tracks allowed)
			(vias allowed)
			(pads allowed)
			(copperpour allowed)
			(footprints allowed)
		)
		(placement
			(enabled no)
			(sheetname "")
		)
		(fill
			(thermal_gap 0.5)
			(thermal_bridge_width 0.5)
			(island_removal_mode 0)
		)
		(polygon
			(pts
				(xy 161.891726 -286.254952) (xy 161.891726 -286.026352) (xy 163.923726 -286.026352) (xy 163.923726 -286.254952)
			)
		)
	)
	(zone
		(layer "F.Cu")
		(hatch none 0.5)
		(connect_pads
			(clearance 0)
		)
		(min_thickness 0.25)
		(keepout
			(tracks allowed)
			(vias allowed)
			(pads allowed)
			(copperpour allowed)
			(footprints allowed)
		)
		(placement
			(enabled no)
			(sheetname "")
		)
		(fill
			(thermal_gap 0.5)
			(thermal_bridge_width 0.5)
			(island_removal_mode 0)
		)
		(polygon
			(pts
				(xy 63.900812 -285.516574) (xy 63.900812 -285.072836) (xy 66.186812 -285.072836) (xy 66.186812 -285.516574)
			)
		)
	)
	(zone
		(layer "F.Cu")
		(hatch none 0.5)
		(connect_pads
			(clearance 0)
		)
		(min_thickness 0.25)
		(keepout
			(tracks allowed)
			(vias allowed)
			(pads allowed)
			(copperpour allowed)
			(footprints allowed)
		)
		(placement
			(enabled no)
			(sheetname "")
		)
		(fill
			(thermal_gap 0.5)
			(thermal_bridge_width 0.5)
			(island_removal_mode 0)
		)
		(polygon
			(pts
				(xy 161.891726 -278.37638) (xy 163.923726 -278.37638) (xy 163.923726 -278.378666) (xy 164.102542 -278.378666)
				(xy 164.102542 -278.615902) (xy 164.240464 -278.615902) (xy 164.283644 -278.659082) (xy 164.283644 -278.791924)
				(xy 164.283644 -279.095962) (xy 164.211 -279.168606) (xy 161.670746 -279.168606) (xy 161.529522 -279.027382)
				(xy 161.529522 -278.830278) (xy 161.611056 -278.748744) (xy 161.611056 -278.37638) (xy 161.708592 -278.37638)
				(xy 161.755582 -278.37638)
			)
		)
	)
	(zone
		(layer "F.Cu")
		(hatch none 0.5)
		(connect_pads
			(clearance 0)
		)
		(min_thickness 0.25)
		(keepout
			(tracks allowed)
			(vias allowed)
			(pads allowed)
			(copperpour allowed)
			(footprints allowed)
		)
		(placement
			(enabled no)
			(sheetname "")
		)
		(fill
			(thermal_gap 0.5)
			(thermal_bridge_width 0.5)
			(island_removal_mode 0)
		)
		(polygon
			(pts
				(xy 44.735242 -283.816552) (xy 44.735242 -283.372814) (xy 47.060358 -283.372814) (xy 47.060358 -283.816552)
			)
		)
	)
	(zone
		(layer "F.Cu")
		(hatch none 0.5)
		(connect_pads
			(clearance 0)
		)
		(min_thickness 0.25)
		(keepout
			(tracks allowed)
			(vias allowed)
			(pads allowed)
			(copperpour allowed)
			(footprints allowed)
		)
		(placement
			(enabled no)
			(sheetname "")
		)
		(fill
			(thermal_gap 0.5)
			(thermal_bridge_width 0.5)
			(island_removal_mode 0)
		)
		(polygon
			(pts
				(xy 176.979326 -201.876406) (xy 179.011326 -201.876406) (xy 179.011326 -202.105006) (xy 176.979326 -202.105006)
				(xy 176.843182 -202.105006) (xy 176.796192 -202.105006) (xy 176.796192 -201.876406) (xy 176.843182 -201.876406)
			)
		)
	)
	(zone
		(layer "F.Cu")
		(hatch none 0.5)
		(connect_pads
			(clearance 0)
		)
		(min_thickness 0.25)
		(keepout
			(tracks allowed)
			(vias allowed)
			(pads allowed)
			(copperpour allowed)
			(footprints allowed)
		)
		(placement
			(enabled no)
			(sheetname "")
		)
		(fill
			(thermal_gap 0.5)
			(thermal_bridge_width 0.5)
			(island_removal_mode 0)
		)
		(polygon
			(pts
				(xy 395.120368 -18.55978) (xy 395.120368 -15.425166) (xy 396.89913 -15.425166) (xy 396.89913 -18.55978)
			)
		)
	)
	(zone
		(layer "F.Cu")
		(hatch none 0.5)
		(connect_pads
			(clearance 0)
		)
		(min_thickness 0.25)
		(keepout
			(tracks allowed)
			(vias allowed)
			(pads allowed)
			(copperpour allowed)
			(footprints allowed)
		)
		(placement
			(enabled no)
			(sheetname "")
		)
		(fill
			(thermal_gap 0.5)
			(thermal_bridge_width 0.5)
			(island_removal_mode 0)
		)
		(polygon
			(pts
				(xy 44.735242 -290.61664) (xy 44.735242 -290.172902) (xy 47.060358 -290.172902) (xy 47.060358 -290.61664)
			)
		)
	)
	(zone
		(layer "F.Cu")
		(hatch none 0.5)
		(connect_pads
			(clearance 0)
		)
		(min_thickness 0.25)
		(keepout
			(tracks allowed)
			(vias allowed)
			(pads allowed)
			(copperpour allowed)
			(footprints allowed)
		)
		(placement
			(enabled no)
			(sheetname "")
		)
		(fill
			(thermal_gap 0.5)
			(thermal_bridge_width 0.5)
			(island_removal_mode 0)
		)
		(polygon
			(pts
				(xy 63.951612 -203.916534) (xy 63.951612 -203.472796) (xy 66.161412 -203.472796) (xy 66.161412 -203.916534)
			)
		)
	)
	(zone
		(layer "F.Cu")
		(hatch none 0.5)
		(connect_pads
			(clearance 0)
		)
		(min_thickness 0.25)
		(keepout
			(tracks allowed)
			(vias allowed)
			(pads allowed)
			(copperpour allowed)
			(footprints allowed)
		)
		(placement
			(enabled no)
			(sheetname "")
		)
		(fill
			(thermal_gap 0.5)
			(thermal_bridge_width 0.5)
			(island_removal_mode 0)
		)
		(polygon
			(pts
				(xy 445.493902 -274.35683) (xy 443.461902 -274.35683) (xy 443.461902 -274.354544) (xy 443.283086 -274.354544)
				(xy 443.283086 -274.117308) (xy 443.146434 -273.980656) (xy 443.140846 -273.980656) (xy 443.101984 -273.941794)
				(xy 443.101984 -273.941286) (xy 443.101984 -273.718274) (xy 443.255654 -273.564604) (xy 445.714882 -273.564604)
				(xy 445.856106 -273.705828) (xy 445.856106 -273.902932) (xy 445.774572 -273.984466) (xy 445.690752 -274.068286)
				(xy 445.690752 -274.35683) (xy 445.677036 -274.35683) (xy 445.630046 -274.35683)
			)
		)
	)
	(zone
		(layer "F.Cu")
		(hatch none 0.5)
		(connect_pads
			(clearance 0)
		)
		(min_thickness 0.25)
		(keepout
			(tracks allowed)
			(vias allowed)
			(pads allowed)
			(copperpour allowed)
			(footprints allowed)
		)
		(placement
			(enabled no)
			(sheetname "")
		)
		(fill
			(thermal_gap 0.5)
			(thermal_bridge_width 0.5)
			(island_removal_mode 0)
		)
		(polygon
			(pts
				(xy 409.831794 -281.154886) (xy 409.831794 -280.926286) (xy 411.863794 -280.926286) (xy 411.863794 -281.154886)
			)
		)
	)
	(zone
		(layer "F.Cu")
		(hatch none 0.5)
		(connect_pads
			(clearance 0)
		)
		(min_thickness 0.25)
		(keepout
			(tracks allowed)
			(vias allowed)
			(pads allowed)
			(copperpour allowed)
			(footprints allowed)
		)
		(placement
			(enabled no)
			(sheetname "")
		)
		(fill
			(thermal_gap 0.5)
			(thermal_bridge_width 0.5)
			(island_removal_mode 0)
		)
		(polygon
			(pts
				(xy 26.20391 -220.9165) (xy 26.20391 -220.472762) (xy 28.529026 -220.472762) (xy 28.529026 -220.9165)
			)
		)
	)
	(zone
		(layer "F.Cu")
		(hatch none 0.5)
		(connect_pads
			(clearance 0)
		)
		(min_thickness 0.25)
		(keepout
			(tracks allowed)
			(vias allowed)
			(pads allowed)
			(copperpour allowed)
			(footprints allowed)
		)
		(placement
			(enabled no)
			(sheetname "")
		)
		(fill
			(thermal_gap 0.5)
			(thermal_bridge_width 0.5)
			(island_removal_mode 0)
		)
		(polygon
			(pts
				(xy 455.094594 -233.326432) (xy 457.126594 -233.326432) (xy 457.126594 -233.555032) (xy 455.094594 -233.555032)
				(xy 454.95845 -233.555032) (xy 454.91146 -233.555032) (xy 454.91146 -233.326432) (xy 454.95845 -233.326432)
			)
		)
	)
	(zone
		(layer "F.Cu")
		(hatch none 0.5)
		(connect_pads
			(clearance 0)
		)
		(min_thickness 0.25)
		(keepout
			(tracks not_allowed)
			(vias allowed)
			(pads allowed)
			(copperpour not_allowed)
			(footprints allowed)
		)
		(placement
			(enabled no)
			(sheetname "")
		)
		(fill
			(thermal_gap 0.5)
			(thermal_bridge_width 0.5)
			(island_removal_mode 0)
		)
		(polygon
			(pts
				(arc
					(start 91.01963 -206.024988)
					(mid 88.924638 -208.11998)
					(end 86.829646 -206.024988)
				)
				(arc
					(start 86.829646 -206.024988)
					(mid 88.924638 -203.929996)
					(end 91.01963 -206.024988)
				)
			)
		)
	)
	(zone
		(layer "F.Cu")
		(hatch none 0.5)
		(connect_pads
			(clearance 0)
		)
		(min_thickness 0.25)
		(keepout
			(tracks allowed)
			(vias allowed)
			(pads allowed)
			(copperpour allowed)
			(footprints allowed)
		)
		(placement
			(enabled no)
			(sheetname "")
		)
		(fill
			(thermal_gap 0.5)
			(thermal_bridge_width 0.5)
			(island_removal_mode 0)
		)
		(polygon
			(pts
				(xy 56.37911 -230.266494) (xy 56.37911 -229.822756) (xy 58.704226 -229.822756) (xy 58.704226 -230.266494)
			)
		)
	)
	(zone
		(layer "F.Cu")
		(hatch none 0.5)
		(connect_pads
			(clearance 0)
		)
		(min_thickness 0.25)
		(keepout
			(tracks allowed)
			(vias allowed)
			(pads allowed)
			(copperpour allowed)
			(footprints allowed)
		)
		(placement
			(enabled no)
			(sheetname "")
		)
		(fill
			(thermal_gap 0.5)
			(thermal_bridge_width 0.5)
			(island_removal_mode 0)
		)
		(polygon
			(pts
				(xy 11.11631 -241.31651) (xy 11.11631 -240.872772) (xy 13.441426 -240.872772) (xy 13.441426 -241.31651)
			)
		)
	)
	(zone
		(layer "F.Cu")
		(hatch none 0.5)
		(connect_pads
			(clearance 0)
		)
		(min_thickness 0.25)
		(keepout
			(tracks allowed)
			(vias allowed)
			(pads allowed)
			(copperpour allowed)
			(footprints allowed)
		)
		(placement
			(enabled no)
			(sheetname "")
		)
		(fill
			(thermal_gap 0.5)
			(thermal_bridge_width 0.5)
			(island_removal_mode 0)
		)
		(polygon
			(pts
				(xy 310.088026 -271.066514) (xy 307.76291 -271.066514) (xy 307.636418 -271.066514) (xy 307.636418 -270.115538)
				(xy 310.157114 -270.115538) (xy 310.157114 -271.066514)
			)
		)
	)
	(zone
		(layer "F.Cu")
		(hatch none 0.5)
		(connect_pads
			(clearance 0)
		)
		(min_thickness 0.25)
		(keepout
			(tracks allowed)
			(vias allowed)
			(pads allowed)
			(copperpour allowed)
			(footprints allowed)
		)
		(placement
			(enabled no)
			(sheetname "")
		)
		(fill
			(thermal_gap 0.5)
			(thermal_bridge_width 0.5)
			(island_removal_mode 0)
		)
		(polygon
			(pts
				(xy 277.58771 -308.46649) (xy 277.58771 -308.022752) (xy 279.912826 -308.022752) (xy 279.912826 -308.46649)
			)
		)
	)
	(zone
		(layer "F.Cu")
		(hatch none 0.5)
		(connect_pads
			(clearance 0)
		)
		(min_thickness 0.25)
		(keepout
			(tracks allowed)
			(vias allowed)
			(pads allowed)
			(copperpour allowed)
			(footprints not_allowed)
		)
		(placement
			(enabled no)
			(sheetname "")
		)
		(fill
			(thermal_gap 0.5)
			(thermal_bridge_width 0.5)
			(island_removal_mode 0)
		)
		(polygon
			(pts
				(xy 336.95005 -79.44993) (xy 365.799878 -79.44993)
				(arc
					(start 365.799878 -19.949922)
					(mid 365.067684 -18.182248)
					(end 363.30001 -17.450054)
				)
				(xy 356.95001 -17.450054)
				(arc
					(start 356.95001 -23.450296)
					(mid 356.899972 -33.457638)
					(end 356.849934 -23.450296)
				)
				(xy 356.849934 -17.450054) (xy 336.95005 -17.450054) (xy 336.95005 -35.450018) (xy 349.400114 -35.450018)
				(xy 349.400114 -61.449966) (xy 336.95005 -61.449966)
			)
		)
	)
	(zone
		(layer "F.Cu")
		(hatch none 0.5)
		(connect_pads
			(clearance 0)
		)
		(min_thickness 0.25)
		(keepout
			(tracks allowed)
			(vias allowed)
			(pads allowed)
			(copperpour allowed)
			(footprints allowed)
		)
		(placement
			(enabled no)
			(sheetname "")
		)
		(fill
			(thermal_gap 0.5)
			(thermal_bridge_width 0.5)
			(island_removal_mode 0)
		)
		(polygon
			(pts
				(xy 458.538326 -299.00499) (xy 458.538326 -298.77639) (xy 460.570326 -298.77639) (xy 460.570326 -299.00499)
			)
		)
	)
	(zone
		(layer "F.Cu")
		(hatch none 0.5)
		(connect_pads
			(clearance 0)
		)
		(min_thickness 0.25)
		(keepout
			(tracks allowed)
			(vias allowed)
			(pads allowed)
			(copperpour allowed)
			(footprints allowed)
		)
		(placement
			(enabled no)
			(sheetname "")
		)
		(fill
			(thermal_gap 0.5)
			(thermal_bridge_width 0.5)
			(island_removal_mode 0)
		)
		(polygon
			(pts
				(xy 141.140688 -404.802594) (xy 141.140688 -399.959576) (xy 143.025114 -399.959576) (xy 143.025114 -404.802594)
			)
		)
	)
	(zone
		(layer "F.Cu")
		(hatch none 0.5)
		(connect_pads
			(clearance 0)
		)
		(min_thickness 0.25)
		(keepout
			(tracks allowed)
			(vias allowed)
			(pads allowed)
			(copperpour allowed)
			(footprints allowed)
		)
		(placement
			(enabled no)
			(sheetname "")
		)
		(fill
			(thermal_gap 0.5)
			(thermal_bridge_width 0.5)
			(island_removal_mode 0)
		)
		(polygon
			(pts
				(xy 165.335458 -213.155022) (xy 165.335458 -212.926422) (xy 167.367458 -212.926422) (xy 167.367458 -213.155022)
			)
		)
	)
	(zone
		(layer "F.Cu")
		(hatch none 0.5)
		(connect_pads
			(clearance 0)
		)
		(min_thickness 0.25)
		(keepout
			(tracks allowed)
			(vias allowed)
			(pads allowed)
			(copperpour allowed)
			(footprints allowed)
		)
		(placement
			(enabled no)
			(sheetname "")
		)
		(fill
			(thermal_gap 0.5)
			(thermal_bridge_width 0.5)
			(island_removal_mode 0)
		)
		(polygon
			(pts
				(xy 424.919394 -295.376346) (xy 426.951394 -295.376346) (xy 426.951394 -295.604946) (xy 424.919394 -295.604946)
				(xy 424.78325 -295.604946) (xy 424.73626 -295.604946) (xy 424.73626 -295.376346) (xy 424.78325 -295.376346)
			)
		)
	)
	(zone
		(layer "F.Cu")
		(hatch none 0.5)
		(connect_pads
			(clearance 0)
		)
		(min_thickness 0.25)
		(keepout
			(tracks allowed)
			(vias allowed)
			(pads allowed)
			(copperpour allowed)
			(footprints allowed)
		)
		(placement
			(enabled no)
			(sheetname "")
		)
		(fill
			(thermal_gap 0.5)
			(thermal_bridge_width 0.5)
			(island_removal_mode 0)
		)
		(polygon
			(pts
				(xy 11.11631 -269.366492) (xy 11.11631 -268.922754) (xy 13.441426 -268.922754) (xy 13.441426 -269.366492)
			)
		)
	)
	(zone
		(layer "F.Cu")
		(hatch none 0.5)
		(connect_pads
			(clearance 0)
		)
		(min_thickness 0.25)
		(keepout
			(tracks allowed)
			(vias allowed)
			(pads allowed)
			(copperpour allowed)
			(footprints allowed)
		)
		(placement
			(enabled no)
			(sheetname "")
		)
		(fill
			(thermal_gap 0.5)
			(thermal_bridge_width 0.5)
			(island_removal_mode 0)
		)
		(polygon
			(pts
				(xy 443.450726 -273.276314) (xy 445.482726 -273.276314) (xy 445.482726 -273.2786) (xy 445.661542 -273.2786)
				(xy 445.661542 -273.515836) (xy 445.842644 -273.696938) (xy 445.858138 -273.712432) (xy 445.858138 -273.901408)
				(xy 445.842644 -273.916902) (xy 445.731646 -274.0279) (xy 445.691006 -274.06854) (xy 443.229746 -274.06854)
				(xy 443.088522 -273.927316) (xy 443.088522 -273.730212) (xy 443.170056 -273.648678) (xy 443.228984 -273.58975)
				(xy 443.228984 -273.276314) (xy 443.267592 -273.276314) (xy 443.314582 -273.276314)
			)
		)
	)
	(zone
		(layer "F.Cu")
		(hatch none 0.5)
		(connect_pads
			(clearance 0)
		)
		(min_thickness 0.25)
		(keepout
			(tracks not_allowed)
			(vias allowed)
			(pads allowed)
			(copperpour not_allowed)
			(footprints allowed)
		)
		(placement
			(enabled no)
			(sheetname "")
		)
		(fill
			(thermal_gap 0.5)
			(thermal_bridge_width 0.5)
			(island_removal_mode 0)
		)
		(polygon
			(pts
				(arc
					(start 456.460098 -347.699838)
					(mid 461.460088 -342.699848)
					(end 466.460078 -347.699838)
				)
				(arc
					(start 466.460078 -347.699838)
					(mid 461.460088 -352.699828)
					(end 456.460098 -347.699838)
				)
			)
		)
	)
	(zone
		(layer "F.Cu")
		(hatch none 0.5)
		(connect_pads
			(clearance 0)
		)
		(min_thickness 0.25)
		(keepout
			(tracks allowed)
			(vias allowed)
			(pads allowed)
			(copperpour allowed)
			(footprints allowed)
		)
		(placement
			(enabled no)
			(sheetname "")
		)
		(fill
			(thermal_gap 0.5)
			(thermal_bridge_width 0.5)
			(island_removal_mode 0)
		)
		(polygon
			(pts
				(xy 195.510658 -247.154954) (xy 195.510658 -246.926354) (xy 197.542658 -246.926354) (xy 197.542658 -247.154954)
			)
		)
	)
	(zone
		(layer "F.Cu")
		(hatch none 0.5)
		(connect_pads
			(clearance 0)
		)
		(min_thickness 0.25)
		(keepout
			(tracks allowed)
			(vias allowed)
			(pads allowed)
			(copperpour allowed)
			(footprints allowed)
		)
		(placement
			(enabled no)
			(sheetname "")
		)
		(fill
			(thermal_gap 0.5)
			(thermal_bridge_width 0.5)
			(island_removal_mode 0)
		)
		(polygon
			(pts
				(xy 157.791658 -282.854908) (xy 157.791658 -282.626308) (xy 159.823658 -282.626308) (xy 159.823658 -282.854908)
			)
		)
	)
	(zone
		(layer "F.Cu")
		(hatch none 0.5)
		(connect_pads
			(clearance 0)
		)
		(min_thickness 0.25)
		(keepout
			(tracks allowed)
			(vias allowed)
			(pads allowed)
			(copperpour allowed)
			(footprints allowed)
		)
		(placement
			(enabled no)
			(sheetname "")
		)
		(fill
			(thermal_gap 0.5)
			(thermal_bridge_width 0.5)
			(island_removal_mode 0)
		)
		(polygon
			(pts
				(xy 214.386922 -55.380128) (xy 214.386922 -53.639466) (xy 216.302336 -53.639466) (xy 216.302336 -55.380128)
			)
		)
	)
	(zone
		(layer "F.Cu")
		(hatch none 0.5)
		(connect_pads
			(clearance 0)
		)
		(min_thickness 0.25)
		(keepout
			(tracks allowed)
			(vias allowed)
			(pads allowed)
			(copperpour allowed)
			(footprints allowed)
		)
		(placement
			(enabled no)
			(sheetname "")
		)
		(fill
			(thermal_gap 0.5)
			(thermal_bridge_width 0.5)
			(island_removal_mode 0)
		)
		(polygon
			(pts
				(xy 458.538326 -198.704962) (xy 458.538326 -198.476362) (xy 460.570326 -198.476362) (xy 460.570326 -198.704962)
			)
		)
	)
	(zone
		(layer "F.Cu")
		(hatch none 0.5)
		(connect_pads
			(clearance 0)
		)
		(min_thickness 0.25)
		(keepout
			(tracks allowed)
			(vias allowed)
			(pads allowed)
			(copperpour allowed)
			(footprints allowed)
		)
		(placement
			(enabled no)
			(sheetname "")
		)
		(fill
			(thermal_gap 0.5)
			(thermal_bridge_width 0.5)
			(island_removal_mode 0)
		)
		(polygon
			(pts
				(xy 195.510658 -220.804994) (xy 195.510658 -220.576394) (xy 197.542658 -220.576394) (xy 197.542658 -220.804994)
			)
		)
	)
	(zone
		(layer "F.Cu")
		(hatch none 0.5)
		(connect_pads
			(clearance 0)
		)
		(min_thickness 0.25)
		(keepout
			(tracks allowed)
			(vias allowed)
			(pads allowed)
			(copperpour allowed)
			(footprints allowed)
		)
		(placement
			(enabled no)
			(sheetname "")
		)
		(fill
			(thermal_gap 0.5)
			(thermal_bridge_width 0.5)
			(island_removal_mode 0)
		)
		(polygon
			(pts
				(xy 292.67531 -286.366458) (xy 292.67531 -285.92272) (xy 295.000426 -285.92272) (xy 295.000426 -286.366458)
			)
		)
	)
	(zone
		(layer "F.Cu")
		(hatch none 0.5)
		(connect_pads
			(clearance 0)
		)
		(min_thickness 0.25)
		(keepout
			(tracks allowed)
			(vias allowed)
			(pads allowed)
			(copperpour allowed)
			(footprints allowed)
		)
		(placement
			(enabled no)
			(sheetname "")
		)
		(fill
			(thermal_gap 0.5)
			(thermal_bridge_width 0.5)
			(island_removal_mode 0)
		)
		(polygon
			(pts
				(xy 277.58771 -212.416644) (xy 277.58771 -211.972906) (xy 279.912826 -211.972906) (xy 279.912826 -212.416644)
			)
		)
	)
	(zone
		(layer "F.Cu")
		(hatch none 0.5)
		(connect_pads
			(clearance 0)
		)
		(min_thickness 0.25)
		(keepout
			(tracks allowed)
			(vias allowed)
			(pads allowed)
			(copperpour allowed)
			(footprints allowed)
		)
		(placement
			(enabled no)
			(sheetname "")
		)
		(fill
			(thermal_gap 0.5)
			(thermal_bridge_width 0.5)
			(island_removal_mode 0)
		)
		(polygon
			(pts
				(xy 334.96758 -216.880948) (xy 335.2546 -216.880948) (xy 335.28508 -216.850468) (xy 335.28508 -216.223088)
				(xy 335.19872 -216.136728) (xy 335.01076 -216.136728) (xy 334.9371 -216.210388) (xy 334.9371 -216.850468)
			)
		)
	)
	(zone
		(layer "F.Cu")
		(hatch none 0.5)
		(connect_pads
			(clearance 0)
		)
		(min_thickness 0.25)
		(keepout
			(tracks allowed)
			(vias allowed)
			(pads allowed)
			(copperpour allowed)
			(footprints allowed)
		)
		(placement
			(enabled no)
			(sheetname "")
		)
		(fill
			(thermal_gap 0.5)
			(thermal_bridge_width 0.5)
			(island_removal_mode 0)
		)
		(polygon
			(pts
				(xy 292.67531 -218.366594) (xy 292.67531 -217.922856) (xy 295.000426 -217.922856) (xy 295.000426 -218.366594)
			)
		)
	)
	(zone
		(layer "F.Cu")
		(hatch none 0.5)
		(connect_pads
			(clearance 0)
		)
		(min_thickness 0.25)
		(keepout
			(tracks allowed)
			(vias allowed)
			(pads allowed)
			(copperpour allowed)
			(footprints allowed)
		)
		(placement
			(enabled no)
			(sheetname "")
		)
		(fill
			(thermal_gap 0.5)
			(thermal_bridge_width 0.5)
			(island_removal_mode 0)
		)
		(polygon
			(pts
				(xy 405.363426 -317.175896) (xy 405.363426 -316.947296) (xy 407.395426 -316.947296) (xy 407.395426 -317.175896)
			)
		)
	)
	(zone
		(layer "F.Cu")
		(hatch none 0.5)
		(connect_pads
			(clearance 0)
		)
		(min_thickness 0.25)
		(keepout
			(tracks allowed)
			(vias allowed)
			(pads allowed)
			(copperpour allowed)
			(footprints allowed)
		)
		(placement
			(enabled no)
			(sheetname "")
		)
		(fill
			(thermal_gap 0.5)
			(thermal_bridge_width 0.5)
			(island_removal_mode 0)
		)
		(polygon
			(pts
				(xy 443.450726 -297.304968) (xy 443.450726 -297.076368) (xy 445.482726 -297.076368) (xy 445.482726 -297.304968)
			)
		)
	)
	(zone
		(layer "F.Cu")
		(hatch none 0.5)
		(connect_pads
			(clearance 0)
		)
		(min_thickness 0.25)
		(keepout
			(tracks allowed)
			(vias allowed)
			(pads allowed)
			(copperpour allowed)
			(footprints allowed)
		)
		(placement
			(enabled no)
			(sheetname "")
		)
		(fill
			(thermal_gap 0.5)
			(thermal_bridge_width 0.5)
			(island_removal_mode 0)
		)
		(polygon
			(pts
				(xy 304.319178 -211.566506) (xy 304.319178 -211.122768) (xy 306.644294 -211.122768) (xy 306.644294 -211.566506)
			)
		)
	)
	(zone
		(layer "F.Cu")
		(hatch none 0.5)
		(connect_pads
			(clearance 0)
		)
		(min_thickness 0.25)
		(keepout
			(tracks allowed)
			(vias allowed)
			(pads allowed)
			(copperpour allowed)
			(footprints allowed)
		)
		(placement
			(enabled no)
			(sheetname "")
		)
		(fill
			(thermal_gap 0.5)
			(thermal_bridge_width 0.5)
			(island_removal_mode 0)
		)
		(polygon
			(pts
				(xy 63.977012 -290.61664) (xy 63.977012 -290.172902) (xy 66.186812 -290.172902) (xy 66.186812 -290.61664)
			)
		)
	)
	(zone
		(layer "F.Cu")
		(hatch none 0.5)
		(connect_pads
			(clearance 0)
		)
		(min_thickness 0.25)
		(keepout
			(tracks allowed)
			(vias allowed)
			(pads allowed)
			(copperpour allowed)
			(footprints not_allowed)
		)
		(placement
			(enabled no)
			(sheetname "")
		)
		(fill
			(thermal_gap 0.5)
			(thermal_bridge_width 0.5)
			(island_removal_mode 0)
		)
		(polygon
			(pts
				(arc
					(start 68.482972 -47.049944)
					(mid 70.383146 -45.14977)
					(end 72.283066 -47.049944)
				)
				(arc
					(start 72.283066 -47.049944)
					(mid 70.383146 -48.949864)
					(end 68.482972 -47.049944)
				)
			)
		)
	)
	(zone
		(layer "F.Cu")
		(hatch none 0.5)
		(connect_pads
			(clearance 0)
		)
		(min_thickness 0.25)
		(keepout
			(tracks not_allowed)
			(vias allowed)
			(pads allowed)
			(copperpour not_allowed)
			(footprints allowed)
		)
		(placement
			(enabled no)
			(sheetname "")
		)
		(fill
			(thermal_gap 0.5)
			(thermal_bridge_width 0.5)
			(island_removal_mode 0)
		)
		(polygon
			(pts
				(xy 326.602598 -345.014296) (xy 326.844914 -345.014296) (xy 326.844914 -344.929968) (xy 326.602598 -344.929968)
			)
		)
	)
	(zone
		(layer "F.Cu")
		(hatch none 0.5)
		(connect_pads
			(clearance 0)
		)
		(min_thickness 0.25)
		(keepout
			(tracks allowed)
			(vias allowed)
			(pads allowed)
			(copperpour allowed)
			(footprints allowed)
		)
		(placement
			(enabled no)
			(sheetname "")
		)
		(fill
			(thermal_gap 0.5)
			(thermal_bridge_width 0.5)
			(island_removal_mode 0)
		)
		(polygon
			(pts
				(xy 443.450726 -199.554846) (xy 443.450726 -199.326246) (xy 445.482726 -199.326246) (xy 445.482726 -199.554846)
			)
		)
	)
	(zone
		(layer "F.Cu")
		(hatch none 0.5)
		(connect_pads
			(clearance 0)
		)
		(min_thickness 0.25)
		(keepout
			(tracks allowed)
			(vias allowed)
			(pads allowed)
			(copperpour allowed)
			(footprints allowed)
		)
		(placement
			(enabled no)
			(sheetname "")
		)
		(fill
			(thermal_gap 0.5)
			(thermal_bridge_width 0.5)
			(island_removal_mode 0)
		)
		(polygon
			(pts
				(xy 307.932582 -410.948886) (xy 307.932582 -406.105868) (xy 309.817008 -406.105868) (xy 309.817008 -410.948886)
			)
		)
	)
	(zone
		(layer "F.Cu")
		(hatch none 0.5)
		(connect_pads
			(clearance 0)
		)
		(min_thickness 0.25)
		(keepout
			(tracks allowed)
			(vias allowed)
			(pads allowed)
			(copperpour allowed)
			(footprints allowed)
		)
		(placement
			(enabled no)
			(sheetname "")
		)
		(fill
			(thermal_gap 0.5)
			(thermal_bridge_width 0.5)
			(island_removal_mode 0)
		)
		(polygon
			(pts
				(xy 418.095176 -161.806128) (xy 416.7632 -161.806128) (xy 416.564318 -161.607246) (xy 416.564318 -159.815276)
				(xy 417.367466 -159.012128) (xy 419.84549 -159.012128) (xy 421.205152 -160.37179) (xy 421.205152 -165.863524)
				(xy 420.065454 -167.003222) (xy 416.144964 -167.003222) (xy 415.51352 -166.371778) (xy 415.51352 -164.655754)
				(xy 416.070034 -164.09924) (xy 418.21862 -164.09924) (xy 418.2872 -164.03066) (xy 418.2872 -161.998152)
			)
		)
	)
	(zone
		(layer "F.Cu")
		(hatch none 0.5)
		(connect_pads
			(clearance 0)
		)
		(min_thickness 0.25)
		(keepout
			(tracks allowed)
			(vias allowed)
			(pads allowed)
			(copperpour allowed)
			(footprints allowed)
		)
		(placement
			(enabled no)
			(sheetname "")
		)
		(fill
			(thermal_gap 0.5)
			(thermal_bridge_width 0.5)
			(island_removal_mode 0)
		)
		(polygon
			(pts
				(xy 330.63688 -76.952348) (xy 332.44028 -76.952348) (xy 332.64348 -76.749148) (xy 332.64348 -75.606148)
				(xy 332.33868 -75.301348) (xy 331.29728 -75.301348) (xy 330.53528 -76.063348) (xy 330.53528 -76.850748)
			)
		)
	)
	(zone
		(layer "F.Cu")
		(hatch none 0.5)
		(connect_pads
			(clearance 0)
		)
		(min_thickness 0.25)
		(keepout
			(tracks allowed)
			(vias allowed)
			(pads allowed)
			(copperpour allowed)
			(footprints allowed)
		)
		(placement
			(enabled no)
			(sheetname "")
		)
		(fill
			(thermal_gap 0.5)
			(thermal_bridge_width 0.5)
			(island_removal_mode 0)
		)
		(polygon
			(pts
				(xy 11.11631 -303.366424) (xy 11.11631 -302.922686) (xy 13.441426 -302.922686) (xy 13.441426 -303.366424)
			)
		)
	)
	(zone
		(layer "F.Cu")
		(hatch none 0.5)
		(connect_pads
			(clearance 0)
		)
		(min_thickness 0.25)
		(keepout
			(tracks allowed)
			(vias allowed)
			(pads allowed)
			(copperpour allowed)
			(footprints allowed)
		)
		(placement
			(enabled no)
			(sheetname "")
		)
		(fill
			(thermal_gap 0.5)
			(thermal_bridge_width 0.5)
			(island_removal_mode 0)
		)
		(polygon
			(pts
				(xy 10.965688 -319.243456) (xy 10.965688 -316.881256) (xy 13.581888 -316.881256) (xy 13.581888 -319.243456)
			)
		)
	)
	(zone
		(layer "F.Cu")
		(hatch none 0.5)
		(connect_pads
			(clearance 0)
		)
		(min_thickness 0.25)
		(keepout
			(tracks allowed)
			(vias allowed)
			(pads allowed)
			(copperpour allowed)
			(footprints allowed)
		)
		(placement
			(enabled no)
			(sheetname "")
		)
		(fill
			(thermal_gap 0.5)
			(thermal_bridge_width 0.5)
			(island_removal_mode 0)
		)
		(polygon
			(pts
				(xy 192.066926 -300.476412) (xy 194.098926 -300.476412) (xy 194.098926 -300.705012) (xy 192.066926 -300.705012)
				(xy 191.930782 -300.705012) (xy 191.883792 -300.705012) (xy 191.817244 -300.705012) (xy 191.817244 -300.476412)
				(xy 191.883792 -300.476412) (xy 191.930782 -300.476412)
			)
		)
	)
	(zone
		(layer "F.Cu")
		(hatch none 0.5)
		(connect_pads
			(clearance 0)
		)
		(min_thickness 0.25)
		(keepout
			(tracks allowed)
			(vias allowed)
			(pads allowed)
			(copperpour allowed)
			(footprints allowed)
		)
		(placement
			(enabled no)
			(sheetname "")
		)
		(fill
			(thermal_gap 0.5)
			(thermal_bridge_width 0.5)
			(island_removal_mode 0)
		)
		(polygon
			(pts
				(xy 455.094594 -278.37638) (xy 457.126594 -278.37638) (xy 457.126594 -278.60498) (xy 455.094594 -278.60498)
				(xy 454.95845 -278.60498) (xy 454.91146 -278.60498) (xy 454.91146 -278.37638) (xy 454.95845 -278.37638)
			)
		)
	)
	(zone
		(layer "F.Cu")
		(hatch none 0.5)
		(connect_pads
			(clearance 0)
		)
		(min_thickness 0.25)
		(keepout
			(tracks allowed)
			(vias allowed)
			(pads allowed)
			(copperpour allowed)
			(footprints allowed)
		)
		(placement
			(enabled no)
			(sheetname "")
		)
		(fill
			(thermal_gap 0.5)
			(thermal_bridge_width 0.5)
			(island_removal_mode 0)
		)
		(polygon
			(pts
				(xy 409.831794 -265.004804) (xy 409.831794 -264.776204) (xy 411.863794 -264.776204) (xy 411.863794 -265.004804)
			)
		)
	)
	(zone
		(layer "F.Cu")
		(hatch none 0.5)
		(connect_pads
			(clearance 0)
		)
		(min_thickness 0.25)
		(keepout
			(tracks allowed)
			(vias allowed)
			(pads allowed)
			(copperpour allowed)
			(footprints allowed)
		)
		(placement
			(enabled no)
			(sheetname "")
		)
		(fill
			(thermal_gap 0.5)
			(thermal_bridge_width 0.5)
			(island_removal_mode 0)
		)
		(polygon
			(pts
				(xy 56.37911 -305.066446) (xy 56.37911 -304.622708) (xy 58.704226 -304.622708) (xy 58.704226 -305.066446)
			)
		)
	)
	(zone
		(layer "F.Cu")
		(hatch none 0.5)
		(connect_pads
			(clearance 0)
		)
		(min_thickness 0.25)
		(keepout
			(tracks allowed)
			(vias allowed)
			(pads allowed)
			(copperpour allowed)
			(footprints allowed)
		)
		(placement
			(enabled no)
			(sheetname "")
		)
		(fill
			(thermal_gap 0.5)
			(thermal_bridge_width 0.5)
			(island_removal_mode 0)
		)
		(polygon
			(pts
				(xy 277.58771 -224.316544) (xy 277.58771 -223.872806) (xy 279.912826 -223.872806) (xy 279.912826 -224.316544)
			)
		)
	)
	(zone
		(layer "F.Cu")
		(hatch none 0.5)
		(connect_pads
			(clearance 0)
		)
		(min_thickness 0.25)
		(keepout
			(tracks allowed)
			(vias allowed)
			(pads allowed)
			(copperpour allowed)
			(footprints allowed)
		)
		(placement
			(enabled no)
			(sheetname "")
		)
		(fill
			(thermal_gap 0.5)
			(thermal_bridge_width 0.5)
			(island_removal_mode 0)
		)
		(polygon
			(pts
				(xy 172.015912 -355.797104) (xy 170.268392 -355.797104) (xy 170.268392 -353.861624) (xy 172.015912 -353.861624)
			)
		)
	)
	(zone
		(layer "F.Cu")
		(hatch none 0.5)
		(connect_pads
			(clearance 0)
		)
		(min_thickness 0.25)
		(keepout
			(tracks allowed)
			(vias allowed)
			(pads allowed)
			(copperpour allowed)
			(footprints allowed)
		)
		(placement
			(enabled no)
			(sheetname "")
		)
		(fill
			(thermal_gap 0.5)
			(thermal_bridge_width 0.5)
			(island_removal_mode 0)
		)
		(polygon
			(pts
				(xy 259.056378 -259.166614) (xy 259.056378 -258.722876) (xy 261.381494 -258.722876) (xy 261.381494 -259.166614)
			)
		)
	)
	(zone
		(layer "F.Cu")
		(hatch none 0.5)
		(connect_pads
			(clearance 0)
		)
		(min_thickness 0.25)
		(keepout
			(tracks allowed)
			(vias allowed)
			(pads allowed)
			(copperpour allowed)
			(footprints allowed)
		)
		(placement
			(enabled no)
			(sheetname "")
		)
		(fill
			(thermal_gap 0.5)
			(thermal_bridge_width 0.5)
			(island_removal_mode 0)
		)
		(polygon
			(pts
				(xy 183.21528 -404.41626) (xy 183.21528 -403.26564) (xy 184.8104 -403.26564) (xy 184.8104 -404.41626)
			)
		)
	)
	(zone
		(layer "F.Cu")
		(hatch none 0.5)
		(connect_pads
			(clearance 0)
		)
		(min_thickness 0.25)
		(keepout
			(tracks allowed)
			(vias allowed)
			(pads allowed)
			(copperpour allowed)
			(footprints allowed)
		)
		(placement
			(enabled no)
			(sheetname "")
		)
		(fill
			(thermal_gap 0.5)
			(thermal_bridge_width 0.5)
			(island_removal_mode 0)
		)
		(polygon
			(pts
				(xy 289.231578 -278.716486) (xy 289.231578 -278.272748) (xy 291.556694 -278.272748) (xy 291.556694 -278.716486)
			)
		)
	)
	(zone
		(layer "F.Cu")
		(hatch none 0.5)
		(connect_pads
			(clearance 0)
		)
		(min_thickness 0.25)
		(keepout
			(tracks allowed)
			(vias allowed)
			(pads allowed)
			(copperpour allowed)
			(footprints allowed)
		)
		(placement
			(enabled no)
			(sheetname "")
		)
		(fill
			(thermal_gap 0.5)
			(thermal_bridge_width 0.5)
			(island_removal_mode 0)
		)
		(polygon
			(pts
				(xy 262.50011 -225.166428) (xy 262.50011 -224.72269) (xy 264.825226 -224.72269) (xy 264.825226 -225.166428)
			)
		)
	)
	(zone
		(layer "F.Cu")
		(hatch none 0.5)
		(connect_pads
			(clearance 0)
		)
		(min_thickness 0.25)
		(keepout
			(tracks allowed)
			(vias allowed)
			(pads allowed)
			(copperpour allowed)
			(footprints allowed)
		)
		(placement
			(enabled no)
			(sheetname "")
		)
		(fill
			(thermal_gap 0.5)
			(thermal_bridge_width 0.5)
			(island_removal_mode 0)
		)
		(polygon
			(pts
				(xy 207.154526 -272.42643) (xy 209.186526 -272.42643) (xy 209.186526 -272.65503) (xy 207.154526 -272.65503)
				(xy 207.018382 -272.65503) (xy 206.971392 -272.65503) (xy 206.971392 -272.42643) (xy 207.018382 -272.42643)
			)
		)
	)
	(zone
		(layer "F.Cu")
		(hatch none 0.5)
		(connect_pads
			(clearance 0)
		)
		(min_thickness 0.25)
		(keepout
			(tracks allowed)
			(vias allowed)
			(pads allowed)
			(copperpour allowed)
			(footprints allowed)
		)
		(placement
			(enabled no)
			(sheetname "")
		)
		(fill
			(thermal_gap 0.5)
			(thermal_bridge_width 0.5)
			(island_removal_mode 0)
		)
		(polygon
			(pts
				(xy 311.91708 -278.272748) (xy 314.10148 -278.272748) (xy 314.250832 -278.272748) (xy 314.250832 -278.65578)
				(xy 314.400946 -278.805894) (xy 314.400946 -279.095962) (xy 314.28817 -279.208738) (xy 311.775602 -279.208738)
				(xy 311.634632 -279.067768) (xy 311.634632 -278.733504) (xy 311.743344 -278.624792) (xy 311.743344 -278.272748)
				(xy 311.794398 -278.272748)
			)
		)
	)
	(zone
		(layer "F.Cu")
		(hatch none 0.5)
		(connect_pads
			(clearance 0)
		)
		(min_thickness 0.25)
		(keepout
			(tracks allowed)
			(vias allowed)
			(pads allowed)
			(copperpour allowed)
			(footprints allowed)
		)
		(placement
			(enabled no)
			(sheetname "")
		)
		(fill
			(thermal_gap 0.5)
			(thermal_bridge_width 0.5)
			(island_removal_mode 0)
		)
		(polygon
			(pts
				(xy 440.006994 -197.626478) (xy 442.038994 -197.626478) (xy 442.038994 -197.855078) (xy 440.006994 -197.855078)
				(xy 439.87085 -197.855078) (xy 439.82386 -197.855078) (xy 439.82386 -197.626478) (xy 439.87085 -197.626478)
			)
		)
	)
	(zone
		(layer "F.Cu")
		(hatch none 0.5)
		(connect_pads
			(clearance 0)
		)
		(min_thickness 0.25)
		(keepout
			(tracks allowed)
			(vias allowed)
			(pads allowed)
			(copperpour allowed)
			(footprints allowed)
		)
		(placement
			(enabled no)
			(sheetname "")
		)
		(fill
			(thermal_gap 0.5)
			(thermal_bridge_width 0.5)
			(island_removal_mode 0)
		)
		(polygon
			(pts
				(xy 458.538326 -276.904958) (xy 458.538326 -276.676358) (xy 460.570326 -276.676358) (xy 460.570326 -276.904958)
			)
		)
	)
	(zone
		(layer "F.Cu")
		(hatch none 0.5)
		(connect_pads
			(clearance 0)
		)
		(min_thickness 0.25)
		(keepout
			(tracks allowed)
			(vias allowed)
			(pads allowed)
			(copperpour allowed)
			(footprints allowed)
		)
		(placement
			(enabled no)
			(sheetname "")
		)
		(fill
			(thermal_gap 0.5)
			(thermal_bridge_width 0.5)
			(island_removal_mode 0)
		)
		(polygon
			(pts
				(xy 14.560042 -245.566438) (xy 14.560042 -245.1227) (xy 16.885158 -245.1227) (xy 16.885158 -245.566438)
			)
		)
	)
	(zone
		(layer "F.Cu")
		(hatch none 0.5)
		(connect_pads
			(clearance 0)
		)
		(min_thickness 0.25)
		(keepout
			(tracks allowed)
			(vias allowed)
			(pads allowed)
			(copperpour allowed)
			(footprints allowed)
		)
		(placement
			(enabled no)
			(sheetname "")
		)
		(fill
			(thermal_gap 0.5)
			(thermal_bridge_width 0.5)
			(island_removal_mode 0)
		)
		(polygon
			(pts
				(xy 289.231578 -214.96655) (xy 289.231578 -214.522812) (xy 291.556694 -214.522812) (xy 291.556694 -214.96655)
			)
		)
	)
	(zone
		(layer "F.Cu")
		(hatch none 0.5)
		(connect_pads
			(clearance 0)
		)
		(min_thickness 0.25)
		(keepout
			(tracks allowed)
			(vias allowed)
			(pads allowed)
			(copperpour allowed)
			(footprints allowed)
		)
		(placement
			(enabled no)
			(sheetname "")
		)
		(fill
			(thermal_gap 0.5)
			(thermal_bridge_width 0.5)
			(island_removal_mode 0)
		)
		(polygon
			(pts
				(xy 165.335458 -205.504796) (xy 165.335458 -205.276196) (xy 167.367458 -205.276196) (xy 167.367458 -205.504796)
			)
		)
	)
	(zone
		(layer "F.Cu")
		(hatch none 0.5)
		(connect_pads
			(clearance 0)
		)
		(min_thickness 0.25)
		(keepout
			(tracks allowed)
			(vias allowed)
			(pads allowed)
			(copperpour allowed)
			(footprints allowed)
		)
		(placement
			(enabled no)
			(sheetname "")
		)
		(fill
			(thermal_gap 0.5)
			(thermal_bridge_width 0.5)
			(island_removal_mode 0)
		)
		(polygon
			(pts
				(xy 44.735242 -267.66647) (xy 44.735242 -267.222732) (xy 47.060358 -267.222732) (xy 47.060358 -267.66647)
			)
		)
	)
	(zone
		(layer "F.Cu")
		(hatch none 0.5)
		(connect_pads
			(clearance 0)
		)
		(min_thickness 0.25)
		(keepout
			(tracks allowed)
			(vias allowed)
			(pads allowed)
			(copperpour allowed)
			(footprints allowed)
		)
		(placement
			(enabled no)
			(sheetname "")
		)
		(fill
			(thermal_gap 0.5)
			(thermal_bridge_width 0.5)
			(island_removal_mode 0)
		)
		(polygon
			(pts
				(xy 26.20391 -250.666504) (xy 26.20391 -250.222766) (xy 28.529026 -250.222766) (xy 28.529026 -250.666504)
			)
		)
	)
	(zone
		(layer "F.Cu")
		(hatch none 0.5)
		(connect_pads
			(clearance 0)
		)
		(min_thickness 0.25)
		(keepout
			(tracks allowed)
			(vias allowed)
			(pads allowed)
			(copperpour allowed)
			(footprints allowed)
		)
		(placement
			(enabled no)
			(sheetname "")
		)
		(fill
			(thermal_gap 0.5)
			(thermal_bridge_width 0.5)
			(island_removal_mode 0)
		)
		(polygon
			(pts
				(xy 386.31876 -284.145228) (xy 386.60578 -284.145228) (xy 386.63626 -284.114748) (xy 386.63626 -283.487368)
				(xy 386.5499 -283.401008) (xy 386.36194 -283.401008) (xy 386.28828 -283.474668) (xy 386.28828 -284.114748)
			)
		)
	)
	(zone
		(layer "F.Cu")
		(hatch none 0.5)
		(connect_pads
			(clearance 0)
		)
		(min_thickness 0.25)
		(keepout
			(tracks allowed)
			(vias allowed)
			(pads allowed)
			(copperpour allowed)
			(footprints allowed)
		)
		(placement
			(enabled no)
			(sheetname "")
		)
		(fill
			(thermal_gap 0.5)
			(thermal_bridge_width 0.5)
			(island_removal_mode 0)
		)
		(polygon
			(pts
				(xy 14.560042 -247.26646) (xy 14.560042 -246.822722) (xy 16.885158 -246.822722) (xy 16.885158 -247.26646)
			)
		)
	)
	(zone
		(layer "F.Cu")
		(hatch none 0.5)
		(connect_pads
			(clearance 0)
		)
		(min_thickness 0.25)
		(keepout
			(tracks allowed)
			(vias allowed)
			(pads allowed)
			(copperpour allowed)
			(footprints allowed)
		)
		(placement
			(enabled no)
			(sheetname "")
		)
		(fill
			(thermal_gap 0.5)
			(thermal_bridge_width 0.5)
			(island_removal_mode 0)
		)
		(polygon
			(pts
				(xy 443.450726 -267.554964) (xy 443.450726 -267.326364) (xy 445.482726 -267.326364) (xy 445.482726 -267.554964)
			)
		)
	)
	(zone
		(layer "F.Cu")
		(hatch none 0.5)
		(connect_pads
			(clearance 0)
		)
		(min_thickness 0.25)
		(keepout
			(tracks allowed)
			(vias allowed)
			(pads allowed)
			(copperpour allowed)
			(footprints allowed)
		)
		(placement
			(enabled no)
			(sheetname "")
		)
		(fill
			(thermal_gap 0.5)
			(thermal_bridge_width 0.5)
			(island_removal_mode 0)
		)
		(polygon
			(pts
				(xy 64.002412 -312.716418) (xy 64.002412 -312.27268) (xy 66.186812 -312.27268) (xy 66.186812 -312.716418)
			)
		)
	)
	(zone
		(layer "F.Cu")
		(hatch none 0.5)
		(connect_pads
			(clearance 0)
		)
		(min_thickness 0.25)
		(keepout
			(tracks allowed)
			(vias allowed)
			(pads allowed)
			(copperpour allowed)
			(footprints allowed)
		)
		(placement
			(enabled no)
			(sheetname "")
		)
		(fill
			(thermal_gap 0.5)
			(thermal_bridge_width 0.5)
			(island_removal_mode 0)
		)
		(polygon
			(pts
				(xy 180.423058 -245.454932) (xy 180.423058 -245.226332) (xy 182.455058 -245.226332) (xy 182.455058 -245.454932)
			)
		)
	)
	(zone
		(layer "F.Cu")
		(hatch none 0.5)
		(connect_pads
			(clearance 0)
		)
		(min_thickness 0.25)
		(keepout
			(tracks allowed)
			(vias allowed)
			(pads allowed)
			(copperpour allowed)
			(footprints allowed)
		)
		(placement
			(enabled no)
			(sheetname "")
		)
		(fill
			(thermal_gap 0.5)
			(thermal_bridge_width 0.5)
			(island_removal_mode 0)
		)
		(polygon
			(pts
				(xy 14.560042 -220.9165) (xy 14.560042 -220.472762) (xy 16.885158 -220.472762) (xy 16.885158 -220.9165)
			)
		)
	)
	(zone
		(layer "F.Cu")
		(hatch none 0.5)
		(connect_pads
			(clearance 0)
		)
		(min_thickness 0.25)
		(keepout
			(tracks allowed)
			(vias allowed)
			(pads allowed)
			(copperpour allowed)
			(footprints allowed)
		)
		(placement
			(enabled no)
			(sheetname "")
		)
		(fill
			(thermal_gap 0.5)
			(thermal_bridge_width 0.5)
			(island_removal_mode 0)
		)
		(polygon
			(pts
				(xy 26.20391 -205.616556) (xy 26.20391 -205.172818) (xy 28.529026 -205.172818) (xy 28.529026 -205.616556)
			)
		)
	)
	(zone
		(layer "F.Cu")
		(hatch none 0.5)
		(connect_pads
			(clearance 0)
		)
		(min_thickness 0.25)
		(keepout
			(tracks allowed)
			(vias allowed)
			(pads allowed)
			(copperpour allowed)
			(footprints allowed)
		)
		(placement
			(enabled no)
			(sheetname "")
		)
		(fill
			(thermal_gap 0.5)
			(thermal_bridge_width 0.5)
			(island_removal_mode 0)
		)
		(polygon
			(pts
				(xy 165.335458 -230.154988) (xy 165.335458 -229.926388) (xy 167.367458 -229.926388) (xy 167.367458 -230.154988)
			)
		)
	)
	(zone
		(layer "F.Cu")
		(hatch none 0.5)
		(connect_pads
			(clearance 0)
		)
		(min_thickness 0.25)
		(keepout
			(tracks allowed)
			(vias allowed)
			(pads allowed)
			(copperpour allowed)
			(footprints allowed)
		)
		(placement
			(enabled no)
			(sheetname "")
		)
		(fill
			(thermal_gap 0.5)
			(thermal_bridge_width 0.5)
			(island_removal_mode 0)
		)
		(polygon
			(pts
				(xy 210.598258 -310.055006) (xy 210.598258 -309.826406) (xy 212.630258 -309.826406) (xy 212.630258 -310.055006)
			)
		)
	)
	(zone
		(layer "F.Cu")
		(hatch none 0.5)
		(connect_pads
			(clearance 0)
		)
		(min_thickness 0.25)
		(keepout
			(tracks allowed)
			(vias allowed)
			(pads allowed)
			(copperpour allowed)
			(footprints allowed)
		)
		(placement
			(enabled no)
			(sheetname "")
		)
		(fill
			(thermal_gap 0.5)
			(thermal_bridge_width 0.5)
			(island_removal_mode 0)
		)
		(polygon
			(pts
				(xy 365.0869 -338.897468) (xy 365.0869 -334.470248) (xy 370.86794 -334.470248) (xy 370.86794 -338.897468)
			)
		)
	)
	(zone
		(layer "F.Cu")
		(hatch none 0.5)
		(connect_pads
			(clearance 0)
		)
		(min_thickness 0.25)
		(keepout
			(tracks allowed)
			(vias allowed)
			(pads allowed)
			(copperpour allowed)
			(footprints allowed)
		)
		(placement
			(enabled no)
			(sheetname "")
		)
		(fill
			(thermal_gap 0.5)
			(thermal_bridge_width 0.5)
			(island_removal_mode 0)
		)
		(polygon
			(pts
				(xy 431.7365 -12.700508) (xy 431.7365 -9.921748) (xy 433.451 -9.921748) (xy 433.451 -12.700508)
			)
		)
	)
	(zone
		(layer "F.Cu")
		(hatch none 0.5)
		(connect_pads
			(clearance 0)
		)
		(min_thickness 0.25)
		(keepout
			(tracks allowed)
			(vias allowed)
			(pads allowed)
			(copperpour allowed)
			(footprints allowed)
		)
		(placement
			(enabled no)
			(sheetname "")
		)
		(fill
			(thermal_gap 0.5)
			(thermal_bridge_width 0.5)
			(island_removal_mode 0)
		)
		(polygon
			(pts
				(xy 364.98022 -38.02888) (xy 364.98022 -35.38474) (xy 363.78896 -35.38474) (xy 363.78896 -38.02888)
			)
		)
	)
	(zone
		(layer "F.Cu")
		(hatch none 0.5)
		(connect_pads
			(clearance 0)
		)
		(min_thickness 0.25)
		(keepout
			(tracks allowed)
			(vias allowed)
			(pads allowed)
			(copperpour allowed)
			(footprints allowed)
		)
		(placement
			(enabled no)
			(sheetname "")
		)
		(fill
			(thermal_gap 0.5)
			(thermal_bridge_width 0.5)
			(island_removal_mode 0)
		)
		(polygon
			(pts
				(xy 210.598258 -196.154802) (xy 210.598258 -195.926202) (xy 212.630258 -195.926202) (xy 212.630258 -196.154802)
			)
		)
	)
	(zone
		(layer "F.Cu")
		(hatch none 0.5)
		(connect_pads
			(clearance 0)
		)
		(min_thickness 0.25)
		(keepout
			(tracks allowed)
			(vias allowed)
			(pads allowed)
			(copperpour allowed)
			(footprints allowed)
		)
		(placement
			(enabled no)
			(sheetname "")
		)
		(fill
			(thermal_gap 0.5)
			(thermal_bridge_width 0.5)
			(island_removal_mode 0)
		)
		(polygon
			(pts
				(xy 455.094594 -216.326466) (xy 457.126594 -216.326466) (xy 457.126594 -216.555066) (xy 455.094594 -216.555066)
				(xy 454.95845 -216.555066) (xy 454.91146 -216.555066) (xy 454.91146 -216.326466) (xy 454.95845 -216.326466)
			)
		)
	)
	(zone
		(layer "F.Cu")
		(hatch none 0.5)
		(connect_pads
			(clearance 0)
		)
		(min_thickness 0.25)
		(keepout
			(tracks allowed)
			(vias allowed)
			(pads allowed)
			(copperpour allowed)
			(footprints not_allowed)
		)
		(placement
			(enabled no)
			(sheetname "")
		)
		(fill
			(thermal_gap 0.5)
			(thermal_bridge_width 0.5)
			(island_removal_mode 0)
		)
		(polygon
			(pts
				(arc
					(start 237.914942 -79.149956)
					(mid 235.89996 -84.950265)
					(end 233.884978 -79.149956)
				)
			)
		)
	)
	(zone
		(layer "F.Cu")
		(hatch none 0.5)
		(connect_pads
			(clearance 0)
		)
		(min_thickness 0.25)
		(keepout
			(tracks allowed)
			(vias allowed)
			(pads allowed)
			(copperpour allowed)
			(footprints allowed)
		)
		(placement
			(enabled no)
			(sheetname "")
		)
		(fill
			(thermal_gap 0.5)
			(thermal_bridge_width 0.5)
			(island_removal_mode 0)
		)
		(polygon
			(pts
				(xy 356.57028 -215.293448) (xy 356.8573 -215.293448) (xy 356.88778 -215.262968) (xy 356.88778 -214.635588)
				(xy 356.80142 -214.549228) (xy 356.61346 -214.549228) (xy 356.5398 -214.622888) (xy 356.5398 -215.262968)
			)
		)
	)
	(zone
		(layer "F.Cu")
		(hatch none 0.5)
		(connect_pads
			(clearance 0)
		)
		(min_thickness 0.25)
		(keepout
			(tracks allowed)
			(vias allowed)
			(pads allowed)
			(copperpour allowed)
			(footprints allowed)
		)
		(placement
			(enabled no)
			(sheetname "")
		)
		(fill
			(thermal_gap 0.5)
			(thermal_bridge_width 0.5)
			(island_removal_mode 0)
		)
		(polygon
			(pts
				(xy 44.735242 -234.516422) (xy 44.735242 -234.072684) (xy 47.060358 -234.072684) (xy 47.060358 -234.516422)
			)
		)
	)
	(zone
		(layer "F.Cu")
		(hatch none 0.5)
		(connect_pads
			(clearance 0)
		)
		(min_thickness 0.25)
		(keepout
			(tracks allowed)
			(vias allowed)
			(pads allowed)
			(copperpour allowed)
			(footprints allowed)
		)
		(placement
			(enabled no)
			(sheetname "")
		)
		(fill
			(thermal_gap 0.5)
			(thermal_bridge_width 0.5)
			(island_removal_mode 0)
		)
		(polygon
			(pts
				(xy 277.58771 -250.666504) (xy 277.58771 -250.222766) (xy 279.912826 -250.222766) (xy 279.912826 -250.666504)
			)
		)
	)
	(zone
		(layer "F.Cu")
		(hatch none 0.5)
		(connect_pads
			(clearance 0)
		)
		(min_thickness 0.25)
		(keepout
			(tracks allowed)
			(vias allowed)
			(pads allowed)
			(copperpour allowed)
			(footprints allowed)
		)
		(placement
			(enabled no)
			(sheetname "")
		)
		(fill
			(thermal_gap 0.5)
			(thermal_bridge_width 0.5)
			(island_removal_mode 0)
		)
		(polygon
			(pts
				(xy 20.3327 -391.2743) (xy 20.3327 -390.09066) (xy 23.50516 -390.09066) (xy 23.50516 -391.2743)
			)
		)
	)
	(zone
		(layer "F.Cu")
		(hatch none 0.5)
		(connect_pads
			(clearance 0)
		)
		(min_thickness 0.25)
		(keepout
			(tracks allowed)
			(vias allowed)
			(pads allowed)
			(copperpour allowed)
			(footprints allowed)
		)
		(placement
			(enabled no)
			(sheetname "")
		)
		(fill
			(thermal_gap 0.5)
			(thermal_bridge_width 0.5)
			(island_removal_mode 0)
		)
		(polygon
			(pts
				(xy 161.891726 -201.254868) (xy 161.891726 -201.026268) (xy 163.923726 -201.026268) (xy 163.923726 -201.254868)
			)
		)
	)
	(zone
		(layer "F.Cu")
		(hatch none 0.5)
		(connect_pads
			(clearance 0)
		)
		(min_thickness 0.25)
		(keepout
			(tracks allowed)
			(vias allowed)
			(pads allowed)
			(copperpour allowed)
			(footprints allowed)
		)
		(placement
			(enabled no)
			(sheetname "")
		)
		(fill
			(thermal_gap 0.5)
			(thermal_bridge_width 0.5)
			(island_removal_mode 0)
		)
		(polygon
			(pts
				(xy 44.735242 -236.216444) (xy 44.735242 -235.772706) (xy 47.060358 -235.772706) (xy 47.060358 -236.216444)
			)
		)
	)
	(zone
		(layer "F.Cu")
		(hatch none 0.5)
		(connect_pads
			(clearance 0)
		)
		(min_thickness 0.25)
		(keepout
			(tracks allowed)
			(vias allowed)
			(pads allowed)
			(copperpour allowed)
			(footprints allowed)
		)
		(placement
			(enabled no)
			(sheetname "")
		)
		(fill
			(thermal_gap 0.5)
			(thermal_bridge_width 0.5)
			(island_removal_mode 0)
		)
		(polygon
			(pts
				(xy 413.275526 -203.805028) (xy 413.275526 -203.576428) (xy 415.307526 -203.576428) (xy 415.307526 -203.805028)
			)
		)
	)
	(zone
		(layer "F.Cu")
		(hatch none 0.5)
		(connect_pads
			(clearance 0)
		)
		(min_thickness 0.25)
		(keepout
			(tracks allowed)
			(vias allowed)
			(pads allowed)
			(copperpour allowed)
			(footprints allowed)
		)
		(placement
			(enabled no)
			(sheetname "")
		)
		(fill
			(thermal_gap 0.5)
			(thermal_bridge_width 0.5)
			(island_removal_mode 0)
		)
		(polygon
			(pts
				(xy 56.37911 -263.416542) (xy 56.37911 -262.972804) (xy 58.704226 -262.972804) (xy 58.704226 -263.416542)
			)
		)
	)
	(zone
		(layer "F.Cu")
		(hatch none 0.5)
		(connect_pads
			(clearance 0)
		)
		(min_thickness 0.25)
		(keepout
			(tracks allowed)
			(vias allowed)
			(pads allowed)
			(copperpour allowed)
			(footprints allowed)
		)
		(placement
			(enabled no)
			(sheetname "")
		)
		(fill
			(thermal_gap 0.5)
			(thermal_bridge_width 0.5)
			(island_removal_mode 0)
		)
		(polygon
			(pts
				(xy 413.982916 -173.354746) (xy 417.988496 -173.354746) (xy 418.468556 -172.874686) (xy 418.468556 -170.809666)
				(xy 418.196776 -170.537886) (xy 416.342576 -170.537886) (xy 416.091116 -170.286426) (xy 416.091116 -168.366186)
				(xy 415.674556 -167.949626) (xy 414.183576 -167.949626) (xy 413.535876 -168.597326) (xy 413.535876 -172.907706)
			)
		)
	)
	(zone
		(layer "F.Cu")
		(hatch none 0.5)
		(connect_pads
			(clearance 0)
		)
		(min_thickness 0.25)
		(keepout
			(tracks allowed)
			(vias allowed)
			(pads allowed)
			(copperpour allowed)
			(footprints allowed)
		)
		(placement
			(enabled no)
			(sheetname "")
		)
		(fill
			(thermal_gap 0.5)
			(thermal_bridge_width 0.5)
			(island_removal_mode 0)
		)
		(polygon
			(pts
				(xy 415.318702 -272.657062) (xy 413.286702 -272.657062) (xy 413.286702 -272.654776) (xy 413.107886 -272.654776)
				(xy 413.107886 -272.41754) (xy 413.053784 -272.41754) (xy 412.926784 -272.29054) (xy 412.926784 -272.241518)
				(xy 412.926784 -271.93748) (xy 412.999428 -271.864836) (xy 415.539682 -271.864836) (xy 415.680906 -272.00606)
				(xy 415.680906 -272.203164) (xy 415.599372 -272.284698) (xy 415.599372 -272.657062) (xy 415.501836 -272.657062)
				(xy 415.454846 -272.657062)
			)
		)
	)
	(zone
		(layer "F.Cu")
		(hatch none 0.5)
		(connect_pads
			(clearance 0)
		)
		(min_thickness 0.25)
		(keepout
			(tracks not_allowed)
			(vias allowed)
			(pads allowed)
			(copperpour not_allowed)
			(footprints allowed)
		)
		(placement
			(enabled no)
			(sheetname "")
		)
		(fill
			(thermal_gap 0.5)
			(thermal_bridge_width 0.5)
			(island_removal_mode 0)
		)
		(polygon
			(pts
				(xy 52.923694 -176.280826) (xy 53.366162 -176.280826) (xy 53.366162 -174.722028) (xy 53.06314 -174.722028)
				(xy 53.06314 -174.667672) (xy 51.272694 -174.667672) (xy 51.272694 -173.042072) (xy 51.50231 -172.812456)
				(xy 51.565302 -172.812456) (xy 51.565302 -172.635926) (xy 51.096164 -172.635926) (xy 51.096164 -176.280826)
				(xy 51.298094 -176.280826) (xy 51.298094 -174.936658) (xy 52.923694 -174.936658)
			)
		)
	)
	(zone
		(layer "F.Cu")
		(hatch none 0.5)
		(connect_pads
			(clearance 0)
		)
		(min_thickness 0.25)
		(keepout
			(tracks allowed)
			(vias allowed)
			(pads allowed)
			(copperpour allowed)
			(footprints allowed)
		)
		(placement
			(enabled no)
			(sheetname "")
		)
		(fill
			(thermal_gap 0.5)
			(thermal_bridge_width 0.5)
			(island_removal_mode 0)
		)
		(polygon
			(pts
				(xy 44.735242 -265.966448) (xy 44.735242 -265.52271) (xy 47.060358 -265.52271) (xy 47.060358 -265.966448)
			)
		)
	)
	(zone
		(layer "F.Cu")
		(hatch none 0.5)
		(connect_pads
			(clearance 0)
		)
		(min_thickness 0.25)
		(keepout
			(tracks allowed)
			(vias allowed)
			(pads allowed)
			(copperpour allowed)
			(footprints allowed)
		)
		(placement
			(enabled no)
			(sheetname "")
		)
		(fill
			(thermal_gap 0.5)
			(thermal_bridge_width 0.5)
			(island_removal_mode 0)
		)
		(polygon
			(pts
				(xy 29.647642 -281.266646) (xy 29.647642 -280.822908) (xy 31.972758 -280.822908) (xy 31.972758 -281.266646)
			)
		)
	)
	(zone
		(layer "F.Cu")
		(hatch none 0.5)
		(connect_pads
			(clearance 0)
		)
		(min_thickness 0.25)
		(keepout
			(tracks allowed)
			(vias allowed)
			(pads allowed)
			(copperpour allowed)
			(footprints allowed)
		)
		(placement
			(enabled no)
			(sheetname "")
		)
		(fill
			(thermal_gap 0.5)
			(thermal_bridge_width 0.5)
			(island_removal_mode 0)
		)
		(polygon
			(pts
				(xy 246.88038 -396.466568) (xy 246.88038 -393.189968) (xy 250.28144 -393.189968) (xy 250.28144 -396.466568)
			)
		)
	)
	(zone
		(layer "F.Cu")
		(hatch none 0.5)
		(connect_pads
			(clearance 0)
		)
		(min_thickness 0.25)
		(keepout
			(tracks allowed)
			(vias allowed)
			(pads allowed)
			(copperpour allowed)
			(footprints not_allowed)
		)
		(placement
			(enabled no)
			(sheetname "")
		)
		(fill
			(thermal_gap 0.5)
			(thermal_bridge_width 0.5)
			(island_removal_mode 0)
		)
		(polygon
			(pts
				(xy 157.812994 -185.092086) (xy 216.719912 -185.092086) (xy 216.719912 -177.092102) (xy 157.812994 -177.092102)
			)
		)
	)
	(zone
		(layer "F.Cu")
		(hatch none 0.5)
		(connect_pads
			(clearance 0)
		)
		(min_thickness 0.25)
		(keepout
			(tracks allowed)
			(vias allowed)
			(pads allowed)
			(copperpour allowed)
			(footprints allowed)
		)
		(placement
			(enabled no)
			(sheetname "")
		)
		(fill
			(thermal_gap 0.5)
			(thermal_bridge_width 0.5)
			(island_removal_mode 0)
		)
		(polygon
			(pts
				(xy 409.831794 -297.304968) (xy 409.831794 -297.076368) (xy 411.863794 -297.076368) (xy 411.863794 -297.304968)
			)
		)
	)
	(zone
		(layer "F.Cu")
		(hatch none 0.5)
		(connect_pads
			(clearance 0)
		)
		(min_thickness 0.25)
		(keepout
			(tracks allowed)
			(vias allowed)
			(pads allowed)
			(copperpour allowed)
			(footprints allowed)
		)
		(placement
			(enabled no)
			(sheetname "")
		)
		(fill
			(thermal_gap 0.5)
			(thermal_bridge_width 0.5)
			(island_removal_mode 0)
		)
		(polygon
			(pts
				(xy 44.735242 -282.966414) (xy 44.735242 -282.522676) (xy 47.060358 -282.522676) (xy 47.060358 -282.966414)
			)
		)
	)
	(zone
		(layer "F.Cu")
		(hatch none 0.5)
		(connect_pads
			(clearance 0)
		)
		(min_thickness 0.25)
		(keepout
			(tracks allowed)
			(vias allowed)
			(pads allowed)
			(copperpour allowed)
			(footprints allowed)
		)
		(placement
			(enabled no)
			(sheetname "")
		)
		(fill
			(thermal_gap 0.5)
			(thermal_bridge_width 0.5)
			(island_removal_mode 0)
		)
		(polygon
			(pts
				(xy 44.735242 -273.61642) (xy 44.735242 -273.172682) (xy 47.060358 -273.172682) (xy 47.060358 -273.61642)
			)
		)
	)
	(zone
		(layer "F.Cu")
		(hatch none 0.5)
		(connect_pads
			(clearance 0)
		)
		(min_thickness 0.25)
		(keepout
			(tracks allowed)
			(vias allowed)
			(pads allowed)
			(copperpour allowed)
			(footprints allowed)
		)
		(placement
			(enabled no)
			(sheetname "")
		)
		(fill
			(thermal_gap 0.5)
			(thermal_bridge_width 0.5)
			(island_removal_mode 0)
		)
		(polygon
			(pts
				(xy 192.066926 -284.556962) (xy 194.098926 -284.556962) (xy 194.098926 -284.328362) (xy 192.066926 -284.328362)
				(xy 191.935608 -284.328362) (xy 191.9097 -284.328362) (xy 191.9097 -284.556962) (xy 191.935608 -284.556962)
			)
		)
	)
	(zone
		(layer "F.Cu")
		(hatch none 0.5)
		(connect_pads
			(clearance 0)
		)
		(min_thickness 0.25)
		(keepout
			(tracks allowed)
			(vias allowed)
			(pads allowed)
			(copperpour allowed)
			(footprints allowed)
		)
		(placement
			(enabled no)
			(sheetname "")
		)
		(fill
			(thermal_gap 0.5)
			(thermal_bridge_width 0.5)
			(island_removal_mode 0)
		)
		(polygon
			(pts
				(xy 195.510658 -226.754944) (xy 195.510658 -226.526344) (xy 197.542658 -226.526344) (xy 197.542658 -226.754944)
			)
		)
	)
	(zone
		(layer "F.Cu")
		(hatch none 0.5)
		(connect_pads
			(clearance 0)
		)
		(min_thickness 0.25)
		(keepout
			(tracks allowed)
			(vias allowed)
			(pads allowed)
			(copperpour allowed)
			(footprints allowed)
		)
		(placement
			(enabled no)
			(sheetname "")
		)
		(fill
			(thermal_gap 0.5)
			(thermal_bridge_width 0.5)
			(island_removal_mode 0)
		)
		(polygon
			(pts
				(xy 180.423058 -207.204818) (xy 180.423058 -206.976218) (xy 182.455058 -206.976218) (xy 182.455058 -207.204818)
			)
		)
	)
	(zone
		(layer "F.Cu")
		(hatch none 0.5)
		(connect_pads
			(clearance 0)
		)
		(min_thickness 0.25)
		(keepout
			(tracks allowed)
			(vias allowed)
			(pads allowed)
			(copperpour allowed)
			(footprints allowed)
		)
		(placement
			(enabled no)
			(sheetname "")
		)
		(fill
			(thermal_gap 0.5)
			(thermal_bridge_width 0.5)
			(island_removal_mode 0)
		)
		(polygon
			(pts
				(xy 180.423058 -216.554812) (xy 180.423058 -216.326212) (xy 182.455058 -216.326212) (xy 182.455058 -216.554812)
			)
		)
	)
	(zone
		(layer "F.Cu")
		(hatch none 0.5)
		(connect_pads
			(clearance 0)
		)
		(min_thickness 0.25)
		(keepout
			(tracks allowed)
			(vias allowed)
			(pads allowed)
			(copperpour allowed)
			(footprints allowed)
		)
		(placement
			(enabled no)
			(sheetname "")
		)
		(fill
			(thermal_gap 0.5)
			(thermal_bridge_width 0.5)
			(island_removal_mode 0)
		)
		(polygon
			(pts
				(xy 289.231578 -314.41644) (xy 289.231578 -313.972702) (xy 291.556694 -313.972702) (xy 291.556694 -314.41644)
			)
		)
	)
	(zone
		(layer "F.Cu")
		(hatch none 0.5)
		(connect_pads
			(clearance 0)
		)
		(min_thickness 0.25)
		(keepout
			(tracks allowed)
			(vias allowed)
			(pads allowed)
			(copperpour allowed)
			(footprints allowed)
		)
		(placement
			(enabled no)
			(sheetname "")
		)
		(fill
			(thermal_gap 0.5)
			(thermal_bridge_width 0.5)
			(island_removal_mode 0)
		)
		(polygon
			(pts
				(xy 259.056378 -312.716418) (xy 259.056378 -312.27268) (xy 261.381494 -312.27268) (xy 261.381494 -312.716418)
			)
		)
	)
	(zone
		(layer "F.Cu")
		(hatch none 0.5)
		(connect_pads
			(clearance 0)
		)
		(min_thickness 0.25)
		(keepout
			(tracks allowed)
			(vias allowed)
			(pads allowed)
			(copperpour allowed)
			(footprints allowed)
		)
		(placement
			(enabled no)
			(sheetname "")
		)
		(fill
			(thermal_gap 0.5)
			(thermal_bridge_width 0.5)
			(island_removal_mode 0)
		)
		(polygon
			(pts
				(xy 274.143978 -276.572726) (xy 276.469094 -276.572726) (xy 276.53488 -276.572726) (xy 276.53488 -277.460456)
				(xy 274.01012 -277.460456) (xy 274.01012 -276.572726)
			)
		)
	)
	(zone
		(layer "F.Cu")
		(hatch none 0.5)
		(connect_pads
			(clearance 0)
		)
		(min_thickness 0.25)
		(keepout
			(tracks allowed)
			(vias allowed)
			(pads allowed)
			(copperpour allowed)
			(footprints allowed)
		)
		(placement
			(enabled no)
			(sheetname "")
		)
		(fill
			(thermal_gap 0.5)
			(thermal_bridge_width 0.5)
			(island_removal_mode 0)
		)
		(polygon
			(pts
				(xy 413.275526 -208.054956) (xy 413.275526 -207.826356) (xy 415.307526 -207.826356) (xy 415.307526 -208.054956)
			)
		)
	)
	(zone
		(layer "F.Cu")
		(hatch none 0.5)
		(connect_pads
			(clearance 0)
		)
		(min_thickness 0.25)
		(keepout
			(tracks allowed)
			(vias allowed)
			(pads allowed)
			(copperpour allowed)
			(footprints allowed)
		)
		(placement
			(enabled no)
			(sheetname "")
		)
		(fill
			(thermal_gap 0.5)
			(thermal_bridge_width 0.5)
			(island_removal_mode 0)
		)
		(polygon
			(pts
				(xy 386.67182 -220.121988) (xy 386.95884 -220.121988) (xy 386.98932 -220.091508) (xy 386.98932 -219.464128)
				(xy 386.90296 -219.377768) (xy 386.715 -219.377768) (xy 386.64134 -219.451428) (xy 386.64134 -220.091508)
			)
		)
	)
	(zone
		(layer "F.Cu")
		(hatch none 0.5)
		(connect_pads
			(clearance 0)
		)
		(min_thickness 0.25)
		(keepout
			(tracks allowed)
			(vias allowed)
			(pads allowed)
			(copperpour allowed)
			(footprints allowed)
		)
		(placement
			(enabled no)
			(sheetname "")
		)
		(fill
			(thermal_gap 0.5)
			(thermal_bridge_width 0.5)
			(island_removal_mode 0)
		)
		(polygon
			(pts
				(xy 384.81508 -216.868248) (xy 385.1021 -216.868248) (xy 385.13258 -216.837768) (xy 385.13258 -216.210388)
				(xy 385.04622 -216.124028) (xy 384.85826 -216.124028) (xy 384.7846 -216.197688) (xy 384.7846 -216.837768)
			)
		)
	)
	(zone
		(layer "F.Cu")
		(hatch none 0.5)
		(connect_pads
			(clearance 0)
		)
		(min_thickness 0.25)
		(keepout
			(tracks allowed)
			(vias allowed)
			(pads allowed)
			(copperpour allowed)
			(footprints allowed)
		)
		(placement
			(enabled no)
			(sheetname "")
		)
		(fill
			(thermal_gap 0.5)
			(thermal_bridge_width 0.5)
			(island_removal_mode 0)
		)
		(polygon
			(pts
				(xy 210.598258 -227.604828) (xy 210.598258 -227.376228) (xy 212.630258 -227.376228) (xy 212.630258 -227.604828)
			)
		)
	)
	(zone
		(layer "F.Cu")
		(hatch none 0.5)
		(connect_pads
			(clearance 0)
		)
		(min_thickness 0.25)
		(keepout
			(tracks allowed)
			(vias allowed)
			(pads allowed)
			(copperpour allowed)
			(footprints allowed)
		)
		(placement
			(enabled no)
			(sheetname "")
		)
		(fill
			(thermal_gap 0.5)
			(thermal_bridge_width 0.5)
			(island_removal_mode 0)
		)
		(polygon
			(pts
				(xy 409.831794 -314.304934) (xy 409.831794 -314.076334) (xy 411.863794 -314.076334) (xy 411.863794 -314.304934)
			)
		)
	)
	(zone
		(layer "F.Cu")
		(hatch none 0.5)
		(connect_pads
			(clearance 0)
		)
		(min_thickness 0.25)
		(keepout
			(tracks allowed)
			(vias allowed)
			(pads allowed)
			(copperpour allowed)
			(footprints allowed)
		)
		(placement
			(enabled no)
			(sheetname "")
		)
		(fill
			(thermal_gap 0.5)
			(thermal_bridge_width 0.5)
			(island_removal_mode 0)
		)
		(polygon
			(pts
				(xy 289.231578 -282.11653) (xy 289.231578 -281.672792) (xy 291.556694 -281.672792) (xy 291.556694 -282.11653)
			)
		)
	)
	(zone
		(layer "F.Cu")
		(hatch none 0.5)
		(connect_pads
			(clearance 0)
		)
		(min_thickness 0.25)
		(keepout
			(tracks allowed)
			(vias allowed)
			(pads allowed)
			(copperpour allowed)
			(footprints allowed)
		)
		(placement
			(enabled no)
			(sheetname "")
		)
		(fill
			(thermal_gap 0.5)
			(thermal_bridge_width 0.5)
			(island_removal_mode 0)
		)
		(polygon
			(pts
				(xy 14.560042 -277.866602) (xy 14.560042 -277.422864) (xy 16.885158 -277.422864) (xy 16.885158 -277.866602)
			)
		)
	)
	(zone
		(layer "F.Cu")
		(hatch none 0.5)
		(connect_pads
			(clearance 0)
		)
		(min_thickness 0.25)
		(keepout
			(tracks allowed)
			(vias allowed)
			(pads allowed)
			(copperpour allowed)
			(footprints allowed)
		)
		(placement
			(enabled no)
			(sheetname "")
		)
		(fill
			(thermal_gap 0.5)
			(thermal_bridge_width 0.5)
			(island_removal_mode 0)
		)
		(polygon
			(pts
				(xy 335.11744 -286.581088) (xy 335.40446 -286.581088) (xy 335.43494 -286.550608) (xy 335.43494 -285.923228)
				(xy 335.34858 -285.836868) (xy 335.16062 -285.836868) (xy 335.08696 -285.910528) (xy 335.08696 -286.550608)
			)
		)
	)
	(zone
		(layer "F.Cu")
		(hatch none 0.5)
		(connect_pads
			(clearance 0)
		)
		(min_thickness 0.25)
		(keepout
			(tracks allowed)
			(vias allowed)
			(pads allowed)
			(copperpour allowed)
			(footprints allowed)
		)
		(placement
			(enabled no)
			(sheetname "")
		)
		(fill
			(thermal_gap 0.5)
			(thermal_bridge_width 0.5)
			(island_removal_mode 0)
		)
		(polygon
			(pts
				(xy 440.006994 -272.42643) (xy 442.038994 -272.42643) (xy 442.038994 -272.428716) (xy 442.21781 -272.428716)
				(xy 442.21781 -272.665952) (xy 442.355732 -272.665952) (xy 442.398912 -272.709132) (xy 442.398912 -272.841974)
				(xy 442.398912 -273.146012) (xy 442.326268 -273.218656) (xy 439.786014 -273.218656) (xy 439.64479 -273.077432)
				(xy 439.64479 -272.880328) (xy 439.726324 -272.798794) (xy 439.726324 -272.42643) (xy 439.82386 -272.42643)
				(xy 439.87085 -272.42643)
			)
		)
	)
	(zone
		(layer "F.Cu")
		(hatch none 0.5)
		(connect_pads
			(clearance 0)
		)
		(min_thickness 0.25)
		(keepout
			(tracks allowed)
			(vias allowed)
			(pads allowed)
			(copperpour allowed)
			(footprints allowed)
		)
		(placement
			(enabled no)
			(sheetname "")
		)
		(fill
			(thermal_gap 0.5)
			(thermal_bridge_width 0.5)
			(island_removal_mode 0)
		)
		(polygon
			(pts
				(xy 311.91708 -290.61664) (xy 311.91708 -290.172902) (xy 314.12688 -290.172902) (xy 314.12688 -290.61664)
			)
		)
	)
	(zone
		(layer "F.Cu")
		(hatch none 0.5)
		(connect_pads
			(clearance 0)
		)
		(min_thickness 0.25)
		(keepout
			(tracks allowed)
			(vias allowed)
			(pads allowed)
			(copperpour allowed)
			(footprints not_allowed)
		)
		(placement
			(enabled no)
			(sheetname "")
		)
		(fill
			(thermal_gap 0.5)
			(thermal_bridge_width 0.5)
			(island_removal_mode 0)
		)
		(polygon
			(pts
				(xy 104.005126 -261.62) (xy 107.63504 -261.62) (xy 107.63504 -237.00994) (xy 104.005126 -237.00994)
			)
		)
	)
	(zone
		(layer "F.Cu")
		(hatch none 0.5)
		(connect_pads
			(clearance 0)
		)
		(min_thickness 0.25)
		(keepout
			(tracks not_allowed)
			(vias allowed)
			(pads allowed)
			(copperpour not_allowed)
			(footprints allowed)
		)
		(placement
			(enabled no)
			(sheetname "")
		)
		(fill
			(thermal_gap 0.5)
			(thermal_bridge_width 0.5)
			(island_removal_mode 0)
		)
		(polygon
			(pts
				(xy 252.837188 -97.368868) (xy 253.07925 -97.368868) (xy 253.07925 -96.985328) (xy 253.02972 -96.985328)
				(xy 253.02972 -96.717612) (xy 252.837188 -96.717612)
			)
		)
	)
	(zone
		(layer "F.Cu")
		(hatch none 0.5)
		(connect_pads
			(clearance 0)
		)
		(min_thickness 0.25)
		(keepout
			(tracks allowed)
			(vias allowed)
			(pads allowed)
			(copperpour allowed)
			(footprints allowed)
		)
		(placement
			(enabled no)
			(sheetname "")
		)
		(fill
			(thermal_gap 0.5)
			(thermal_bridge_width 0.5)
			(island_removal_mode 0)
		)
		(polygon
			(pts
				(xy 133.54812 -348.112588) (xy 133.54812 -343.497408) (xy 139.68222 -343.497408) (xy 139.68222 -348.112588)
			)
		)
	)
	(zone
		(layer "F.Cu")
		(hatch none 0.5)
		(connect_pads
			(clearance 0)
		)
		(min_thickness 0.25)
		(keepout
			(tracks allowed)
			(vias allowed)
			(pads allowed)
			(copperpour allowed)
			(footprints allowed)
		)
		(placement
			(enabled no)
			(sheetname "")
		)
		(fill
			(thermal_gap 0.5)
			(thermal_bridge_width 0.5)
			(island_removal_mode 0)
		)
		(polygon
			(pts
				(xy 197.553834 -272.657062) (xy 195.521834 -272.657062) (xy 195.521834 -272.654776) (xy 195.343018 -272.654776)
				(xy 195.343018 -272.41754) (xy 195.205096 -272.41754) (xy 195.161916 -272.37436) (xy 195.161916 -272.241518)
				(xy 195.161916 -271.93748) (xy 195.23456 -271.864836) (xy 197.774814 -271.864836) (xy 197.916038 -272.00606)
				(xy 197.916038 -272.203164) (xy 197.834504 -272.284698) (xy 197.834504 -272.657062) (xy 197.736968 -272.657062)
				(xy 197.689978 -272.657062)
			)
		)
	)
	(zone
		(layer "F.Cu")
		(hatch none 0.5)
		(connect_pads
			(clearance 0)
		)
		(min_thickness 0.25)
		(keepout
			(tracks allowed)
			(vias allowed)
			(pads allowed)
			(copperpour allowed)
			(footprints allowed)
		)
		(placement
			(enabled no)
			(sheetname "")
		)
		(fill
			(thermal_gap 0.5)
			(thermal_bridge_width 0.5)
			(island_removal_mode 0)
		)
		(polygon
			(pts
				(xy 289.231578 -312.716418) (xy 289.231578 -312.27268) (xy 291.556694 -312.27268) (xy 291.556694 -312.716418)
			)
		)
	)
	(zone
		(layer "F.Cu")
		(hatch none 0.5)
		(connect_pads
			(clearance 0)
		)
		(min_thickness 0.25)
		(keepout
			(tracks allowed)
			(vias allowed)
			(pads allowed)
			(copperpour allowed)
			(footprints allowed)
		)
		(placement
			(enabled no)
			(sheetname "")
		)
		(fill
			(thermal_gap 0.5)
			(thermal_bridge_width 0.5)
			(island_removal_mode 0)
		)
		(polygon
			(pts
				(xy 384.44424 -287.416748) (xy 384.73126 -287.416748) (xy 384.76174 -287.386268) (xy 384.76174 -286.758888)
				(xy 384.67538 -286.672528) (xy 384.48742 -286.672528) (xy 384.41376 -286.746188) (xy 384.41376 -287.386268)
			)
		)
	)
	(zone
		(layer "F.Cu")
		(hatch none 0.5)
		(connect_pads
			(clearance 0)
		)
		(min_thickness 0.25)
		(keepout
			(tracks allowed)
			(vias allowed)
			(pads allowed)
			(copperpour allowed)
			(footprints allowed)
		)
		(placement
			(enabled no)
			(sheetname "")
		)
		(fill
			(thermal_gap 0.5)
			(thermal_bridge_width 0.5)
			(island_removal_mode 0)
		)
		(polygon
			(pts
				(xy 359.44556 -215.275668) (xy 359.73258 -215.275668) (xy 359.76306 -215.245188) (xy 359.76306 -214.617808)
				(xy 359.6767 -214.531448) (xy 359.48874 -214.531448) (xy 359.41508 -214.605108) (xy 359.41508 -215.245188)
			)
		)
	)
	(zone
		(layer "F.Cu")
		(hatch none 0.5)
		(connect_pads
			(clearance 0)
		)
		(min_thickness 0.25)
		(keepout
			(tracks allowed)
			(vias allowed)
			(pads allowed)
			(copperpour allowed)
			(footprints allowed)
		)
		(placement
			(enabled no)
			(sheetname "")
		)
		(fill
			(thermal_gap 0.5)
			(thermal_bridge_width 0.5)
			(island_removal_mode 0)
		)
		(polygon
			(pts
				(xy 56.37911 -291.466524) (xy 56.37911 -291.022786) (xy 58.704226 -291.022786) (xy 58.704226 -291.466524)
			)
		)
	)
	(zone
		(layer "F.Cu")
		(hatch none 0.5)
		(connect_pads
			(clearance 0)
		)
		(min_thickness 0.25)
		(keepout
			(tracks allowed)
			(vias allowed)
			(pads allowed)
			(copperpour allowed)
			(footprints allowed)
		)
		(placement
			(enabled no)
			(sheetname "")
		)
		(fill
			(thermal_gap 0.5)
			(thermal_bridge_width 0.5)
			(island_removal_mode 0)
		)
		(polygon
			(pts
				(xy 443.450726 -287.954974) (xy 443.450726 -287.726374) (xy 445.482726 -287.726374) (xy 445.482726 -287.954974)
			)
		)
	)
	(zone
		(layer "F.Cu")
		(hatch none 0.5)
		(connect_pads
			(clearance 0)
		)
		(min_thickness 0.25)
		(keepout
			(tracks allowed)
			(vias allowed)
			(pads allowed)
			(copperpour allowed)
			(footprints allowed)
		)
		(placement
			(enabled no)
			(sheetname "")
		)
		(fill
			(thermal_gap 0.5)
			(thermal_bridge_width 0.5)
			(island_removal_mode 0)
		)
		(polygon
			(pts
				(xy 443.450726 -292.204902) (xy 443.450726 -291.976302) (xy 445.482726 -291.976302) (xy 445.482726 -292.204902)
			)
		)
	)
	(zone
		(layer "F.Cu")
		(hatch none 0.5)
		(connect_pads
			(clearance 0)
		)
		(min_thickness 0.25)
		(keepout
			(tracks allowed)
			(vias allowed)
			(pads allowed)
			(copperpour allowed)
			(footprints allowed)
		)
		(placement
			(enabled no)
			(sheetname "")
		)
		(fill
			(thermal_gap 0.5)
			(thermal_bridge_width 0.5)
			(island_removal_mode 0)
		)
		(polygon
			(pts
				(xy 41.29151 -265.966448) (xy 41.29151 -265.52271) (xy 43.616626 -265.52271) (xy 43.616626 -265.966448)
			)
		)
	)
	(zone
		(layer "F.Cu")
		(hatch none 0.5)
		(connect_pads
			(clearance 0)
		)
		(min_thickness 0.25)
		(keepout
			(tracks allowed)
			(vias allowed)
			(pads allowed)
			(copperpour allowed)
			(footprints allowed)
		)
		(placement
			(enabled no)
			(sheetname "")
		)
		(fill
			(thermal_gap 0.5)
			(thermal_bridge_width 0.5)
			(island_removal_mode 0)
		)
		(polygon
			(pts
				(xy 455.094594 -300.476412) (xy 457.126594 -300.476412) (xy 457.126594 -300.705012) (xy 455.094594 -300.705012)
				(xy 454.95845 -300.705012) (xy 454.91146 -300.705012) (xy 454.91146 -300.476412) (xy 454.95845 -300.476412)
			)
		)
	)
	(zone
		(layer "F.Cu")
		(hatch none 0.5)
		(connect_pads
			(clearance 0)
		)
		(min_thickness 0.25)
		(keepout
			(tracks allowed)
			(vias allowed)
			(pads allowed)
			(copperpour allowed)
			(footprints allowed)
		)
		(placement
			(enabled no)
			(sheetname "")
		)
		(fill
			(thermal_gap 0.5)
			(thermal_bridge_width 0.5)
			(island_removal_mode 0)
		)
		(polygon
			(pts
				(xy 25.78862 -162.715448) (xy 27.24404 -162.715448) (xy 27.58694 -162.372548) (xy 27.58694 -161.163508)
				(xy 26.02484 -159.601408) (xy 23.1267 -159.601408) (xy 21.96084 -160.767268) (xy 21.96084 -161.260028)
				(xy 23.114 -162.413188) (xy 23.114 -166.461948) (xy 23.05812 -166.517828) (xy 23.05812 -167.450008)
				(xy 23.77186 -168.163748) (xy 24.59736 -168.163748) (xy 25.5143 -167.246808) (xy 25.5143 -162.989768)
			)
		)
	)
	(zone
		(layer "F.Cu")
		(hatch none 0.5)
		(connect_pads
			(clearance 0)
		)
		(min_thickness 0.25)
		(keepout
			(tracks allowed)
			(vias allowed)
			(pads allowed)
			(copperpour allowed)
			(footprints allowed)
		)
		(placement
			(enabled no)
			(sheetname "")
		)
		(fill
			(thermal_gap 0.5)
			(thermal_bridge_width 0.5)
			(island_removal_mode 0)
		)
		(polygon
			(pts
				(xy 383.4638 -289.034728) (xy 383.75082 -289.034728) (xy 383.7813 -289.004248) (xy 383.7813 -288.376868)
				(xy 383.69494 -288.290508) (xy 383.50698 -288.290508) (xy 383.43332 -288.364168) (xy 383.43332 -289.004248)
			)
		)
	)
	(zone
		(layer "F.Cu")
		(hatch none 0.5)
		(connect_pads
			(clearance 0)
		)
		(min_thickness 0.25)
		(keepout
			(tracks allowed)
			(vias allowed)
			(pads allowed)
			(copperpour allowed)
			(footprints allowed)
		)
		(placement
			(enabled no)
			(sheetname "")
		)
		(fill
			(thermal_gap 0.5)
			(thermal_bridge_width 0.5)
			(island_removal_mode 0)
		)
		(polygon
			(pts
				(xy 14.560042 -305.066446) (xy 14.560042 -304.622708) (xy 16.885158 -304.622708) (xy 16.885158 -305.066446)
			)
		)
	)
	(zone
		(layer "F.Cu")
		(hatch none 0.5)
		(connect_pads
			(clearance 0)
		)
		(min_thickness 0.25)
		(keepout
			(tracks allowed)
			(vias allowed)
			(pads allowed)
			(copperpour allowed)
			(footprints allowed)
		)
		(placement
			(enabled no)
			(sheetname "")
		)
		(fill
			(thermal_gap 0.5)
			(thermal_bridge_width 0.5)
			(island_removal_mode 0)
		)
		(polygon
			(pts
				(xy 41.29151 -299.116496) (xy 41.29151 -298.672758) (xy 43.616626 -298.672758) (xy 43.616626 -299.116496)
			)
		)
	)
	(zone
		(layer "F.Cu")
		(hatch none 0.5)
		(connect_pads
			(clearance 0)
		)
		(min_thickness 0.25)
		(keepout
			(tracks allowed)
			(vias allowed)
			(pads allowed)
			(copperpour allowed)
			(footprints allowed)
		)
		(placement
			(enabled no)
			(sheetname "")
		)
		(fill
			(thermal_gap 0.5)
			(thermal_bridge_width 0.5)
			(island_removal_mode 0)
		)
		(polygon
			(pts
				(xy 195.510658 -225.904806) (xy 195.510658 -225.676206) (xy 197.542658 -225.676206) (xy 197.542658 -225.904806)
			)
		)
	)
	(zone
		(layer "F.Cu")
		(hatch none 0.5)
		(connect_pads
			(clearance 0)
		)
		(min_thickness 0.25)
		(keepout
			(tracks allowed)
			(vias allowed)
			(pads allowed)
			(copperpour allowed)
			(footprints allowed)
		)
		(placement
			(enabled no)
			(sheetname "")
		)
		(fill
			(thermal_gap 0.5)
			(thermal_bridge_width 0.5)
			(island_removal_mode 0)
		)
		(polygon
			(pts
				(xy 443.450726 -247.154954) (xy 443.450726 -246.926354) (xy 445.482726 -246.926354) (xy 445.482726 -247.154954)
			)
		)
	)
	(zone
		(layer "F.Cu")
		(hatch none 0.5)
		(connect_pads
			(clearance 0)
		)
		(min_thickness 0.25)
		(keepout
			(tracks allowed)
			(vias allowed)
			(pads allowed)
			(copperpour allowed)
			(footprints allowed)
		)
		(placement
			(enabled no)
			(sheetname "")
		)
		(fill
			(thermal_gap 0.5)
			(thermal_bridge_width 0.5)
			(island_removal_mode 0)
		)
		(polygon
			(pts
				(xy 259.056378 -233.666538) (xy 259.056378 -233.2228) (xy 261.381494 -233.2228) (xy 261.381494 -233.666538)
			)
		)
	)
	(zone
		(layer "F.Cu")
		(hatch none 0.5)
		(connect_pads
			(clearance 0)
		)
		(min_thickness 0.25)
		(keepout
			(tracks allowed)
			(vias allowed)
			(pads allowed)
			(copperpour allowed)
			(footprints allowed)
		)
		(placement
			(enabled no)
			(sheetname "")
		)
		(fill
			(thermal_gap 0.5)
			(thermal_bridge_width 0.5)
			(island_removal_mode 0)
		)
		(polygon
			(pts
				(xy 56.37911 -211.566506) (xy 56.37911 -211.122768) (xy 58.704226 -211.122768) (xy 58.704226 -211.566506)
			)
		)
	)
	(zone
		(layer "F.Cu")
		(hatch none 0.5)
		(connect_pads
			(clearance 0)
		)
		(min_thickness 0.25)
		(keepout
			(tracks allowed)
			(vias allowed)
			(pads allowed)
			(copperpour allowed)
			(footprints allowed)
		)
		(placement
			(enabled no)
			(sheetname "")
		)
		(fill
			(thermal_gap 0.5)
			(thermal_bridge_width 0.5)
			(island_removal_mode 0)
		)
		(polygon
			(pts
				(xy 44.735242 -212.416644) (xy 44.735242 -211.972906) (xy 47.060358 -211.972906) (xy 47.060358 -212.416644)
			)
		)
	)
	(zone
		(layer "F.Cu")
		(hatch none 0.5)
		(connect_pads
			(clearance 0)
		)
		(min_thickness 0.25)
		(keepout
			(tracks allowed)
			(vias allowed)
			(pads allowed)
			(copperpour allowed)
			(footprints allowed)
		)
		(placement
			(enabled no)
			(sheetname "")
		)
		(fill
			(thermal_gap 0.5)
			(thermal_bridge_width 0.5)
			(island_removal_mode 0)
		)
		(polygon
			(pts
				(xy 440.006994 -231.62641) (xy 442.038994 -231.62641) (xy 442.038994 -231.85501) (xy 440.006994 -231.85501)
				(xy 439.87085 -231.85501) (xy 439.82386 -231.85501) (xy 439.82386 -231.62641) (xy 439.87085 -231.62641)
			)
		)
	)
	(zone
		(layer "F.Cu")
		(hatch none 0.5)
		(connect_pads
			(clearance 0)
		)
		(min_thickness 0.25)
		(keepout
			(tracks allowed)
			(vias allowed)
			(pads allowed)
			(copperpour allowed)
			(footprints allowed)
		)
		(placement
			(enabled no)
			(sheetname "")
		)
		(fill
			(thermal_gap 0.5)
			(thermal_bridge_width 0.5)
			(island_removal_mode 0)
		)
		(polygon
			(pts
				(xy 176.979326 -287.726374) (xy 179.011326 -287.726374) (xy 179.011326 -287.954974) (xy 176.979326 -287.954974)
				(xy 176.843182 -287.954974) (xy 176.796192 -287.954974) (xy 176.796192 -287.726374) (xy 176.843182 -287.726374)
			)
		)
	)
	(zone
		(layer "F.Cu")
		(hatch none 0.5)
		(connect_pads
			(clearance 0)
		)
		(min_thickness 0.25)
		(keepout
			(tracks allowed)
			(vias allowed)
			(pads allowed)
			(copperpour allowed)
			(footprints allowed)
		)
		(placement
			(enabled no)
			(sheetname "")
		)
		(fill
			(thermal_gap 0.5)
			(thermal_bridge_width 0.5)
			(island_removal_mode 0)
		)
		(polygon
			(pts
				(xy 137.26414 -217.742008) (xy 137.55116 -217.742008) (xy 137.58164 -217.711528) (xy 137.58164 -217.084148)
				(xy 137.49528 -216.997788) (xy 137.30732 -216.997788) (xy 137.23366 -217.071448) (xy 137.23366 -217.711528)
			)
		)
	)
	(zone
		(layer "F.Cu")
		(hatch none 0.5)
		(connect_pads
			(clearance 0)
		)
		(min_thickness 0.25)
		(keepout
			(tracks allowed)
			(vias allowed)
			(pads allowed)
			(copperpour allowed)
			(footprints allowed)
		)
		(placement
			(enabled no)
			(sheetname "")
		)
		(fill
			(thermal_gap 0.5)
			(thermal_bridge_width 0.5)
			(island_removal_mode 0)
		)
		(polygon
			(pts
				(xy 440.006994 -237.57636) (xy 442.038994 -237.57636) (xy 442.038994 -237.578646) (xy 442.21781 -237.578646)
				(xy 442.21781 -237.815882) (xy 442.398912 -237.996984) (xy 442.414406 -238.012478) (xy 442.414406 -238.201454)
				(xy 442.398912 -238.216948) (xy 442.287914 -238.327946) (xy 442.247274 -238.368586) (xy 439.786014 -238.368586)
				(xy 439.64479 -238.227362) (xy 439.64479 -238.030258) (xy 439.726324 -237.948724) (xy 439.785252 -237.889796)
				(xy 439.785252 -237.57636) (xy 439.82386 -237.57636) (xy 439.87085 -237.57636)
			)
		)
	)
	(zone
		(layer "F.Cu")
		(hatch none 0.5)
		(connect_pads
			(clearance 0)
		)
		(min_thickness 0.25)
		(keepout
			(tracks allowed)
			(vias allowed)
			(pads allowed)
			(copperpour allowed)
			(footprints allowed)
		)
		(placement
			(enabled no)
			(sheetname "")
		)
		(fill
			(thermal_gap 0.5)
			(thermal_bridge_width 0.5)
			(island_removal_mode 0)
		)
		(polygon
			(pts
				(xy 289.231578 -264.266426) (xy 289.231578 -263.822688) (xy 291.556694 -263.822688) (xy 291.556694 -264.266426)
			)
		)
	)
	(zone
		(layer "F.Cu")
		(hatch none 0.5)
		(connect_pads
			(clearance 0)
		)
		(min_thickness 0.25)
		(keepout
			(tracks allowed)
			(vias allowed)
			(pads allowed)
			(copperpour allowed)
			(footprints allowed)
		)
		(placement
			(enabled no)
			(sheetname "")
		)
		(fill
			(thermal_gap 0.5)
			(thermal_bridge_width 0.5)
			(island_removal_mode 0)
		)
		(polygon
			(pts
				(xy 413.275526 -205.504796) (xy 413.275526 -205.276196) (xy 415.307526 -205.276196) (xy 415.307526 -205.504796)
			)
		)
	)
	(zone
		(layer "F.Cu")
		(hatch none 0.5)
		(connect_pads
			(clearance 0)
		)
		(min_thickness 0.25)
		(keepout
			(tracks allowed)
			(vias allowed)
			(pads allowed)
			(copperpour allowed)
			(footprints allowed)
		)
		(placement
			(enabled no)
			(sheetname "")
		)
		(fill
			(thermal_gap 0.5)
			(thermal_bridge_width 0.5)
			(island_removal_mode 0)
		)
		(polygon
			(pts
				(xy 409.831794 -211.455) (xy 409.831794 -211.2264) (xy 411.863794 -211.2264) (xy 411.863794 -211.455)
			)
		)
	)
	(zone
		(layer "F.Cu")
		(hatch none 0.5)
		(connect_pads
			(clearance 0)
		)
		(min_thickness 0.25)
		(keepout
			(tracks allowed)
			(vias allowed)
			(pads allowed)
			(copperpour allowed)
			(footprints allowed)
		)
		(placement
			(enabled no)
			(sheetname "")
		)
		(fill
			(thermal_gap 0.5)
			(thermal_bridge_width 0.5)
			(island_removal_mode 0)
		)
		(polygon
			(pts
				(xy 139.244578 -231.901746) (xy 139.447524 -231.6988) (xy 139.447524 -231.65562) (xy 139.003786 -231.211882)
				(xy 138.881612 -231.211882) (xy 138.74877 -231.344978) (xy 138.74877 -231.449118) (xy 139.201398 -231.901746)
			)
		)
	)
	(zone
		(layer "F.Cu")
		(hatch none 0.5)
		(connect_pads
			(clearance 0)
		)
		(min_thickness 0.25)
		(keepout
			(tracks not_allowed)
			(vias allowed)
			(pads allowed)
			(copperpour not_allowed)
			(footprints allowed)
		)
		(placement
			(enabled no)
			(sheetname "")
		)
		(fill
			(thermal_gap 0.5)
			(thermal_bridge_width 0.5)
			(island_removal_mode 0)
		)
		(polygon
			(pts
				(arc
					(start 10.999978 -435.59984)
					(mid 12.999974 -433.599844)
					(end 14.99997 -435.59984)
				)
				(arc
					(start 14.99997 -435.59984)
					(mid 12.999974 -437.599836)
					(end 10.999978 -435.59984)
				)
			)
		)
	)
	(zone
		(layer "F.Cu")
		(hatch none 0.5)
		(connect_pads
			(clearance 0)
		)
		(min_thickness 0.25)
		(keepout
			(tracks allowed)
			(vias allowed)
			(pads allowed)
			(copperpour allowed)
			(footprints allowed)
		)
		(placement
			(enabled no)
			(sheetname "")
		)
		(fill
			(thermal_gap 0.5)
			(thermal_bridge_width 0.5)
			(island_removal_mode 0)
		)
		(polygon
			(pts
				(xy 262.50011 -296.56659) (xy 262.50011 -296.122852) (xy 264.825226 -296.122852) (xy 264.825226 -296.56659)
			)
		)
	)
	(zone
		(layer "F.Cu")
		(hatch none 0.5)
		(connect_pads
			(clearance 0)
		)
		(min_thickness 0.25)
		(keepout
			(tracks allowed)
			(vias allowed)
			(pads allowed)
			(copperpour allowed)
			(footprints allowed)
		)
		(placement
			(enabled no)
			(sheetname "")
		)
		(fill
			(thermal_gap 0.5)
			(thermal_bridge_width 0.5)
			(island_removal_mode 0)
		)
		(polygon
			(pts
				(xy 259.056378 -280.416508) (xy 259.056378 -279.97277) (xy 261.381494 -279.97277) (xy 261.381494 -280.416508)
			)
		)
	)
	(zone
		(layer "F.Cu")
		(hatch none 0.5)
		(connect_pads
			(clearance 0)
		)
		(min_thickness 0.25)
		(keepout
			(tracks not_allowed)
			(vias allowed)
			(pads allowed)
			(copperpour not_allowed)
			(footprints allowed)
		)
		(placement
			(enabled no)
			(sheetname "")
		)
		(fill
			(thermal_gap 0.5)
			(thermal_bridge_width 0.5)
			(island_removal_mode 0)
		)
		(polygon
			(pts
				(xy 111.274352 -336.26044) (xy 115.2144 -336.26044) (xy 115.2144 -336.255868) (xy 115.03406 -336.075528)
				(xy 113.662206 -336.075528) (xy 113.662206 -333.916528) (xy 115.81892 -333.916528) (xy 115.81892 -333.666846)
				(xy 113.48466 -333.666846) (xy 113.48466 -333.974948) (xy 113.37544 -333.974948) (xy 113.370868 -333.97952)
				(xy 113.370868 -336.019902) (xy 111.516668 -336.019902) (xy 111.516668 -335.778856) (xy 111.274352 -335.778856)
			)
		)
	)
	(zone
		(layer "F.Cu")
		(hatch none 0.5)
		(connect_pads
			(clearance 0)
		)
		(min_thickness 0.25)
		(keepout
			(tracks allowed)
			(vias allowed)
			(pads allowed)
			(copperpour allowed)
			(footprints allowed)
		)
		(placement
			(enabled no)
			(sheetname "")
		)
		(fill
			(thermal_gap 0.5)
			(thermal_bridge_width 0.5)
			(island_removal_mode 0)
		)
		(polygon
			(pts
				(xy 41.29151 -228.566472) (xy 41.29151 -228.122734) (xy 43.616626 -228.122734) (xy 43.616626 -228.566472)
			)
		)
	)
	(zone
		(layer "F.Cu")
		(hatch none 0.5)
		(connect_pads
			(clearance 0)
		)
		(min_thickness 0.25)
		(keepout
			(tracks allowed)
			(vias allowed)
			(pads allowed)
			(copperpour allowed)
			(footprints allowed)
		)
		(placement
			(enabled no)
			(sheetname "")
		)
		(fill
			(thermal_gap 0.5)
			(thermal_bridge_width 0.5)
			(island_removal_mode 0)
		)
		(polygon
			(pts
				(xy 443.450726 -222.505016) (xy 443.450726 -222.276416) (xy 445.482726 -222.276416) (xy 445.482726 -222.505016)
			)
		)
	)
	(zone
		(layer "F.Cu")
		(hatch none 0.5)
		(connect_pads
			(clearance 0)
		)
		(min_thickness 0.25)
		(keepout
			(tracks allowed)
			(vias allowed)
			(pads allowed)
			(copperpour allowed)
			(footprints allowed)
		)
		(placement
			(enabled no)
			(sheetname "")
		)
		(fill
			(thermal_gap 0.5)
			(thermal_bridge_width 0.5)
			(island_removal_mode 0)
		)
		(polygon
			(pts
				(xy 274.143978 -211.566506) (xy 274.143978 -211.122768) (xy 276.469094 -211.122768) (xy 276.469094 -211.566506)
			)
		)
	)
	(zone
		(layer "F.Cu")
		(hatch none 0.5)
		(connect_pads
			(clearance 0)
		)
		(min_thickness 0.25)
		(keepout
			(tracks allowed)
			(vias allowed)
			(pads allowed)
			(copperpour allowed)
			(footprints allowed)
		)
		(placement
			(enabled no)
			(sheetname "")
		)
		(fill
			(thermal_gap 0.5)
			(thermal_bridge_width 0.5)
			(island_removal_mode 0)
		)
		(polygon
			(pts
				(xy 307.76291 -301.666656) (xy 307.76291 -301.222918) (xy 310.088026 -301.222918) (xy 310.088026 -301.666656)
			)
		)
	)
	(zone
		(layer "F.Cu")
		(hatch none 0.5)
		(connect_pads
			(clearance 0)
		)
		(min_thickness 0.25)
		(keepout
			(tracks allowed)
			(vias allowed)
			(pads allowed)
			(copperpour allowed)
			(footprints allowed)
		)
		(placement
			(enabled no)
			(sheetname "")
		)
		(fill
			(thermal_gap 0.5)
			(thermal_bridge_width 0.5)
			(island_removal_mode 0)
		)
		(polygon
			(pts
				(xy 44.735242 -197.116446) (xy 44.735242 -196.672708) (xy 47.060358 -196.672708) (xy 47.060358 -197.116446)
			)
		)
	)
	(zone
		(layer "F.Cu")
		(hatch none 0.5)
		(connect_pads
			(clearance 0)
		)
		(min_thickness 0.25)
		(keepout
			(tracks allowed)
			(vias allowed)
			(pads allowed)
			(copperpour allowed)
			(footprints allowed)
		)
		(placement
			(enabled no)
			(sheetname "")
		)
		(fill
			(thermal_gap 0.5)
			(thermal_bridge_width 0.5)
			(island_removal_mode 0)
		)
		(polygon
			(pts
				(xy 329.375262 -410.948886) (xy 329.375262 -406.105868) (xy 331.259688 -406.105868) (xy 331.259688 -410.948886)
			)
		)
	)
	(zone
		(layer "F.Cu")
		(hatch none 0.5)
		(connect_pads
			(clearance 0)
		)
		(min_thickness 0.25)
		(keepout
			(tracks allowed)
			(vias allowed)
			(pads allowed)
			(copperpour allowed)
			(footprints allowed)
		)
		(placement
			(enabled no)
			(sheetname "")
		)
		(fill
			(thermal_gap 0.5)
			(thermal_bridge_width 0.5)
			(island_removal_mode 0)
		)
		(polygon
			(pts
				(xy 289.080956 -319.243456) (xy 289.080956 -316.881256) (xy 291.697156 -316.881256) (xy 291.697156 -319.243456)
			)
		)
	)
	(zone
		(layer "F.Cu")
		(hatch none 0.5)
		(connect_pads
			(clearance 0)
		)
		(min_thickness 0.25)
		(keepout
			(tracks allowed)
			(vias allowed)
			(pads allowed)
			(copperpour allowed)
			(footprints allowed)
		)
		(placement
			(enabled no)
			(sheetname "")
		)
		(fill
			(thermal_gap 0.5)
			(thermal_bridge_width 0.5)
			(island_removal_mode 0)
		)
		(polygon
			(pts
				(xy 307.76291 -214.96655) (xy 307.76291 -214.522812) (xy 310.088026 -214.522812) (xy 310.088026 -214.96655)
			)
		)
	)
	(zone
		(layer "F.Cu")
		(hatch none 0.5)
		(connect_pads
			(clearance 0)
		)
		(min_thickness 0.25)
		(keepout
			(tracks allowed)
			(vias allowed)
			(pads allowed)
			(copperpour allowed)
			(footprints allowed)
		)
		(placement
			(enabled no)
			(sheetname "")
		)
		(fill
			(thermal_gap 0.5)
			(thermal_bridge_width 0.5)
			(island_removal_mode 0)
		)
		(polygon
			(pts
				(xy 14.560042 -282.966414) (xy 14.560042 -282.522676) (xy 16.885158 -282.522676) (xy 16.885158 -282.966414)
			)
		)
	)
	(zone
		(layer "F.Cu")
		(hatch none 0.5)
		(connect_pads
			(clearance 0)
		)
		(min_thickness 0.25)
		(keepout
			(tracks allowed)
			(vias allowed)
			(pads allowed)
			(copperpour allowed)
			(footprints allowed)
		)
		(placement
			(enabled no)
			(sheetname "")
		)
		(fill
			(thermal_gap 0.5)
			(thermal_bridge_width 0.5)
			(island_removal_mode 0)
		)
		(polygon
			(pts
				(xy 292.67531 -208.166462) (xy 292.67531 -207.722724) (xy 295.000426 -207.722724) (xy 295.000426 -208.166462)
			)
		)
	)
	(zone
		(layer "F.Cu")
		(hatch none 0.5)
		(connect_pads
			(clearance 0)
		)
		(min_thickness 0.25)
		(keepout
			(tracks allowed)
			(vias allowed)
			(pads allowed)
			(copperpour allowed)
			(footprints not_allowed)
		)
		(placement
			(enabled no)
			(sheetname "")
		)
		(fill
			(thermal_gap 0.5)
			(thermal_bridge_width 0.5)
			(island_removal_mode 0)
		)
		(polygon
			(pts
				(xy 33.536636 -433.07) (xy 54.200044 -433.07) (xy 54.200044 -409.88996) (xy 48.200056 -409.88996)
				(xy 48.200056 -403.770084) (xy 33.536636 -403.770084)
			)
		)
	)
	(zone
		(layer "F.Cu")
		(hatch none 0.5)
		(connect_pads
			(clearance 0)
		)
		(min_thickness 0.25)
		(keepout
			(tracks allowed)
			(vias allowed)
			(pads allowed)
			(copperpour allowed)
			(footprints allowed)
		)
		(placement
			(enabled no)
			(sheetname "")
		)
		(fill
			(thermal_gap 0.5)
			(thermal_bridge_width 0.5)
			(island_removal_mode 0)
		)
		(polygon
			(pts
				(xy 26.20391 -222.616522) (xy 26.20391 -222.172784) (xy 28.529026 -222.172784) (xy 28.529026 -222.616522)
			)
		)
	)
	(zone
		(layer "F.Cu")
		(hatch none 0.5)
		(connect_pads
			(clearance 0)
		)
		(min_thickness 0.25)
		(keepout
			(tracks allowed)
			(vias allowed)
			(pads allowed)
			(copperpour allowed)
			(footprints allowed)
		)
		(placement
			(enabled no)
			(sheetname "")
		)
		(fill
			(thermal_gap 0.5)
			(thermal_bridge_width 0.5)
			(island_removal_mode 0)
		)
		(polygon
			(pts
				(xy 458.538326 -291.355018) (xy 458.538326 -291.126418) (xy 460.570326 -291.126418) (xy 460.570326 -291.355018)
			)
		)
	)
	(zone
		(layer "F.Cu")
		(hatch none 0.5)
		(connect_pads
			(clearance 0)
		)
		(min_thickness 0.25)
		(keepout
			(tracks allowed)
			(vias allowed)
			(pads allowed)
			(copperpour allowed)
			(footprints allowed)
		)
		(placement
			(enabled no)
			(sheetname "")
		)
		(fill
			(thermal_gap 0.5)
			(thermal_bridge_width 0.5)
			(island_removal_mode 0)
		)
		(polygon
			(pts
				(xy 167.367458 -239.504982) (xy 165.335458 -239.504982) (xy 165.149276 -239.504982) (xy 165.149276 -238.750856)
				(xy 167.567356 -238.750856) (xy 167.567356 -239.504982)
			)
		)
	)
	(zone
		(layer "F.Cu")
		(hatch none 0.5)
		(connect_pads
			(clearance 0)
		)
		(min_thickness 0.25)
		(keepout
			(tracks allowed)
			(vias allowed)
			(pads allowed)
			(copperpour allowed)
			(footprints allowed)
		)
		(placement
			(enabled no)
			(sheetname "")
		)
		(fill
			(thermal_gap 0.5)
			(thermal_bridge_width 0.5)
			(island_removal_mode 0)
		)
		(polygon
			(pts
				(xy 304.319178 -202.216512) (xy 304.319178 -201.772774) (xy 306.644294 -201.772774) (xy 306.644294 -202.216512)
			)
		)
	)
	(zone
		(layer "F.Cu")
		(hatch none 0.5)
		(connect_pads
			(clearance 0)
		)
		(min_thickness 0.25)
		(keepout
			(tracks allowed)
			(vias allowed)
			(pads allowed)
			(copperpour allowed)
			(footprints allowed)
		)
		(placement
			(enabled no)
			(sheetname "")
		)
		(fill
			(thermal_gap 0.5)
			(thermal_bridge_width 0.5)
			(island_removal_mode 0)
		)
		(polygon
			(pts
				(xy 311.94248 -312.716418) (xy 311.94248 -312.27268) (xy 314.12688 -312.27268) (xy 314.12688 -312.716418)
			)
		)
	)
	(zone
		(layer "F.Cu")
		(hatch none 0.5)
		(connect_pads
			(clearance 0)
		)
		(min_thickness 0.25)
		(keepout
			(tracks allowed)
			(vias allowed)
			(pads allowed)
			(copperpour allowed)
			(footprints allowed)
		)
		(placement
			(enabled no)
			(sheetname "")
		)
		(fill
			(thermal_gap 0.5)
			(thermal_bridge_width 0.5)
			(island_removal_mode 0)
		)
		(polygon
			(pts
				(xy 65.83426 -27.066748) (xy 69.81952 -27.066748) (xy 69.81952 -28.814268) (xy 65.83426 -28.814268)
			)
		)
	)
	(zone
		(layer "F.Cu")
		(hatch none 0.5)
		(connect_pads
			(clearance 0)
		)
		(min_thickness 0.25)
		(keepout
			(tracks allowed)
			(vias allowed)
			(pads allowed)
			(copperpour allowed)
			(footprints allowed)
		)
		(placement
			(enabled no)
			(sheetname "")
		)
		(fill
			(thermal_gap 0.5)
			(thermal_bridge_width 0.5)
			(island_removal_mode 0)
		)
		(polygon
			(pts
				(xy 167.378634 -272.657062) (xy 165.346634 -272.657062) (xy 165.346634 -272.654776) (xy 165.167818 -272.654776)
				(xy 165.167818 -272.41754) (xy 165.113716 -272.41754) (xy 164.986716 -272.29054) (xy 164.986716 -272.241518)
				(xy 164.986716 -271.93748) (xy 165.05936 -271.864836) (xy 167.599614 -271.864836) (xy 167.740838 -272.00606)
				(xy 167.740838 -272.203164) (xy 167.659304 -272.284698) (xy 167.659304 -272.657062) (xy 167.561768 -272.657062)
				(xy 167.514778 -272.657062)
			)
		)
	)
	(zone
		(layer "F.Cu")
		(hatch none 0.5)
		(connect_pads
			(clearance 0)
		)
		(min_thickness 0.25)
		(keepout
			(tracks allowed)
			(vias allowed)
			(pads allowed)
			(copperpour allowed)
			(footprints allowed)
		)
		(placement
			(enabled no)
			(sheetname "")
		)
		(fill
			(thermal_gap 0.5)
			(thermal_bridge_width 0.5)
			(island_removal_mode 0)
		)
		(polygon
			(pts
				(xy 207.154526 -225.67646) (xy 209.186526 -225.67646) (xy 209.186526 -225.90506) (xy 207.154526 -225.90506)
				(xy 207.018382 -225.90506) (xy 206.971392 -225.90506) (xy 206.971392 -225.67646) (xy 207.018382 -225.67646)
			)
		)
	)
	(zone
		(layer "F.Cu")
		(hatch none 0.5)
		(connect_pads
			(clearance 0)
		)
		(min_thickness 0.25)
		(keepout
			(tracks allowed)
			(vias allowed)
			(pads allowed)
			(copperpour allowed)
			(footprints allowed)
		)
		(placement
			(enabled no)
			(sheetname "")
		)
		(fill
			(thermal_gap 0.5)
			(thermal_bridge_width 0.5)
			(island_removal_mode 0)
		)
		(polygon
			(pts
				(xy 41.291764 -220.066362) (xy 41.291764 -219.622624) (xy 43.61688 -219.622624) (xy 43.61688 -220.066362)
			)
		)
	)
	(zone
		(layer "F.Cu")
		(hatch none 0.5)
		(connect_pads
			(clearance 0)
		)
		(min_thickness 0.25)
		(keepout
			(tracks allowed)
			(vias allowed)
			(pads allowed)
			(copperpour allowed)
			(footprints allowed)
		)
		(placement
			(enabled no)
			(sheetname "")
		)
		(fill
			(thermal_gap 0.5)
			(thermal_bridge_width 0.5)
			(island_removal_mode 0)
		)
		(polygon
			(pts
				(xy 289.231578 -272.766536) (xy 289.231578 -272.322798) (xy 291.556694 -272.322798) (xy 291.556694 -272.766536)
			)
		)
	)
	(zone
		(layer "F.Cu")
		(hatch none 0.5)
		(connect_pads
			(clearance 0)
		)
		(min_thickness 0.25)
		(keepout
			(tracks allowed)
			(vias allowed)
			(pads allowed)
			(copperpour allowed)
			(footprints allowed)
		)
		(placement
			(enabled no)
			(sheetname "")
		)
		(fill
			(thermal_gap 0.5)
			(thermal_bridge_width 0.5)
			(island_removal_mode 0)
		)
		(polygon
			(pts
				(xy 440.006994 -229.926388) (xy 442.038994 -229.926388) (xy 442.038994 -230.154988) (xy 440.006994 -230.154988)
				(xy 439.87085 -230.154988) (xy 439.82386 -230.154988) (xy 439.82386 -229.926388) (xy 439.87085 -229.926388)
			)
		)
	)
	(zone
		(layer "F.Cu")
		(hatch none 0.5)
		(connect_pads
			(clearance 0)
		)
		(min_thickness 0.25)
		(keepout
			(tracks allowed)
			(vias allowed)
			(pads allowed)
			(copperpour allowed)
			(footprints allowed)
		)
		(placement
			(enabled no)
			(sheetname "")
		)
		(fill
			(thermal_gap 0.5)
			(thermal_bridge_width 0.5)
			(island_removal_mode 0)
		)
		(polygon
			(pts
				(xy 172.879258 -269.254986) (xy 172.879258 -269.026386) (xy 174.911258 -269.026386) (xy 174.911258 -269.254986)
			)
		)
	)
	(zone
		(layer "F.Cu")
		(hatch none 0.5)
		(connect_pads
			(clearance 0)
		)
		(min_thickness 0.25)
		(keepout
			(tracks allowed)
			(vias allowed)
			(pads allowed)
			(copperpour allowed)
			(footprints allowed)
		)
		(placement
			(enabled no)
			(sheetname "")
		)
		(fill
			(thermal_gap 0.5)
			(thermal_bridge_width 0.5)
			(island_removal_mode 0)
		)
		(polygon
			(pts
				(xy 207.154526 -289.426396) (xy 209.186526 -289.426396) (xy 209.186526 -289.654996) (xy 207.154526 -289.654996)
				(xy 207.018382 -289.654996) (xy 206.971392 -289.654996) (xy 206.971392 -289.426396) (xy 207.018382 -289.426396)
			)
		)
	)
	(zone
		(layer "F.Cu")
		(hatch none 0.5)
		(connect_pads
			(clearance 0)
		)
		(min_thickness 0.25)
		(keepout
			(tracks allowed)
			(vias allowed)
			(pads allowed)
			(copperpour allowed)
			(footprints allowed)
		)
		(placement
			(enabled no)
			(sheetname "")
		)
		(fill
			(thermal_gap 0.5)
			(thermal_bridge_width 0.5)
			(island_removal_mode 0)
		)
		(polygon
			(pts
				(xy 26.20391 -291.466524) (xy 26.20391 -291.022786) (xy 28.529026 -291.022786) (xy 28.529026 -291.466524)
			)
		)
	)
	(zone
		(layer "F.Cu")
		(hatch none 0.5)
		(connect_pads
			(clearance 0)
		)
		(min_thickness 0.25)
		(keepout
			(tracks allowed)
			(vias allowed)
			(pads allowed)
			(copperpour allowed)
			(footprints allowed)
		)
		(placement
			(enabled no)
			(sheetname "")
		)
		(fill
			(thermal_gap 0.5)
			(thermal_bridge_width 0.5)
			(island_removal_mode 0)
		)
		(polygon
			(pts
				(xy 443.450726 -224.204784) (xy 443.450726 -223.976184) (xy 445.482726 -223.976184) (xy 445.482726 -224.204784)
			)
		)
	)
	(zone
		(layer "F.Cu")
		(hatch none 0.5)
		(connect_pads
			(clearance 0)
		)
		(min_thickness 0.25)
		(keepout
			(tracks allowed)
			(vias allowed)
			(pads allowed)
			(copperpour allowed)
			(footprints allowed)
		)
		(placement
			(enabled no)
			(sheetname "")
		)
		(fill
			(thermal_gap 0.5)
			(thermal_bridge_width 0.5)
			(island_removal_mode 0)
		)
		(polygon
			(pts
				(xy 417.834572 -153.953718) (xy 417.834572 -155.769818) (xy 416.455352 -155.769818) (xy 416.455352 -153.953718)
			)
		)
	)
	(zone
		(layer "F.Cu")
		(hatch none 0.5)
		(connect_pads
			(clearance 0)
		)
		(min_thickness 0.25)
		(keepout
			(tracks allowed)
			(vias allowed)
			(pads allowed)
			(copperpour allowed)
			(footprints not_allowed)
		)
		(placement
			(enabled no)
			(sheetname "")
		)
		(fill
			(thermal_gap 0.5)
			(thermal_bridge_width 0.5)
			(island_removal_mode 0)
		)
		(polygon
			(pts
				(xy 2.999994 -144.763236)
				(arc
					(start 2.999994 -157.318202)
					(mid 17.770157 -157.535653)
					(end 7.20598 -167.860472)
				)
				(xy 7.20598 -168.661842) (xy 72.497188 -168.661842) (xy 72.497188 -187.661804) (xy 67.04711 -187.661804)
				(xy 67.04711 -328.521822) (xy 72.497188 -328.521822) (xy 72.497188 -347.521784)
				(arc
					(start 18.338038 -347.521784)
					(mid 18.203015 -349.174352)
					(end 17.730216 -350.763586)
				)
				(xy 22.540468 -350.763586) (xy 22.53996 -355.763576) (xy 75.924918 -355.763576) (xy 75.924918 -348.836488)
				(arc
					(start 75.924918 -340.51494)
					(mid 76.305671 -339.595721)
					(end 77.22489 -339.214968)
				)
				(xy 82.4484 -339.214968) (xy 82.4484 -314.770008) (xy 68.929758 -314.770008) (xy 68.929758 -188.770006)
				(xy 84.68995 -188.770006) (xy 84.68995 -165.970712) (xy 139.939776 -165.970712) (xy 139.939776 -188.770006)
				(xy 154.92984 -188.770006) (xy 154.92984 -314.770008) (xy 136.181338 -314.770008) (xy 136.181338 -339.214968)
				(arc
					(start 141.248638 -339.214968)
					(mid 142.167857 -339.595721)
					(end 142.54861 -340.51494)
				)
				(xy 142.54861 -348.836488) (xy 142.54861 -355.763576) (xy 201.33945 -355.763576) (xy 201.33945 -350.763586)
				(xy 215.674956 -350.763586) (xy 215.674956 -347.521784) (xy 151.363426 -347.521784) (xy 151.363426 -328.521822)
				(xy 156.813504 -328.521822) (xy 156.813504 -187.661804) (xy 151.363426 -187.661804) (xy 151.363426 -168.661842)
				(xy 217.670126 -168.661842)
				(arc
					(start 217.670126 -165.699948)
					(mid 218.841697 -162.871527)
					(end 221.670118 -161.699956)
				)
				(xy 222.899986 -161.699956)
				(arc
					(start 222.899986 -93.199966)
					(mid 223.339452 -92.139382)
					(end 224.40011 -91.700096)
				)
				(arc
					(start 247.400064 -91.700096)
					(mid 248.460632 -92.139398)
					(end 248.899934 -93.199966)
				)
				(xy 248.899934 -161.699956)
				(arc
					(start 250.130056 -161.699956)
					(mid 252.958477 -162.871527)
					(end 254.130048 -165.699948)
				)
				(xy 254.130048 -168.661842) (xy 320.437256 -168.661842) (xy 320.437256 -187.661804) (xy 314.987178 -187.661804)
				(xy 314.987178 -328.521822) (xy 320.437256 -328.521822) (xy 320.437256 -347.521784) (xy 256.124964 -347.521784)
				(xy 256.124964 -350.763586) (xy 270.480282 -350.763586) (xy 270.480028 -355.76383) (xy 323.864986 -355.76383)
				(xy 323.864986 -348.836234)
				(arc
					(start 323.864986 -340.51494)
					(mid 324.245739 -339.595721)
					(end 325.164958 -339.214968)
				)
				(xy 330.499212 -339.214968) (xy 330.499212 -314.770008) (xy 316.869826 -314.770008) (xy 316.869826 -188.770006)
				(xy 332.629764 -188.770006) (xy 332.629764 -165.970712) (xy 388.13613 -165.970712) (xy 388.13613 -188.770006)
				(xy 402.869908 -188.770006) (xy 402.869908 -314.770008) (xy 384.122168 -314.770008) (xy 384.122168 -339.214968)
				(arc
					(start 389.188706 -339.214968)
					(mid 390.107925 -339.595721)
					(end 390.488678 -340.51494)
				)
				(xy 390.488678 -348.836234) (xy 390.488678 -355.763576) (xy 449.279518 -355.769672) (xy 449.279518 -350.763586)
				(arc
					(start 454.069704 -350.763586)
					(mid 453.613938 -349.26188)
					(end 453.460104 -347.700092)
				)
				(xy 453.461882 -347.521784) (xy 399.303494 -347.521784) (xy 399.303494 -328.521822) (xy 404.753572 -328.521822)
				(xy 404.753572 -187.661804) (xy 399.303494 -187.661804) (xy 399.303494 -168.661842) (xy 464.59394 -168.661842)
				(arc
					(start 464.59394 -167.860472)
					(mid 453.632353 -158.848444)
					(end 467.300056 -155.032456)
				)
				(xy 467.300056 -144.763236) (xy 452.394066 -144.763236) (xy 452.394066 -161.308542) (xy 431.394108 -161.306256)
				(xy 431.395632 -144.763236) (xy 288.395664 -144.763236) (xy 288.393886 -161.291524) (xy 267.393928 -161.289492)
				(xy 267.395706 -144.763236) (xy 249.99569 -144.763236) (xy 250.003564 -79.76362) (xy 282.50261 -79.76362)
				(xy 282.504642 -59.99099) (xy 303.502568 -59.993276) (xy 303.502314 -79.76362) (xy 416.302444 -79.76362)
				(xy 416.30473 -60.00496) (xy 437.304688 -60.007246) (xy 437.302656 -79.76362) (xy 469.122252 -79.76362)
				(arc
					(start 470.50706 -78.378558)
					(mid 470.723764 -78.054238)
					(end 470.799922 -77.671676)
				)
				(arc
					(start 470.799922 -27.591512)
					(mid 468.736982 -29.26421)
					(end 466.240114 -30.169358)
				)
				(arc
					(start 466.240114 -30.169358)
					(mid 467.055897 -31.098753)
					(end 467.350094 -32.29991)
				)
				(arc
					(start 467.350094 -33.90011)
					(mid 464.75015 -36.500054)
					(end 462.149952 -33.90011)
				)
				(arc
					(start 462.149952 -32.29991)
					(mid 462.450108 -31.087255)
					(end 463.281268 -30.154626)
				)
				(arc
					(start 463.281268 -30.154626)
					(mid 457.855565 -18.328491)
					(end 470.799922 -17.008602)
				)
				(arc
					(start 470.799922 -13.780008)
					(mid 470.507029 -13.072903)
					(end 469.799924 -12.78001)
				)
				(arc
					(start 458.20203 -12.78001)
					(mid 457.439506 -12.681485)
					(end 456.727052 -12.392406)
				)
				(xy 456.727052 -12.850114) (xy 387.08711 -12.850114)
				(arc
					(start 387.08711 -12.386564)
					(mid 386.370156 -12.679988)
					(end 385.601972 -12.78001)
				)
				(arc
					(start 260.800088 -12.78001)
					(mid 260.092983 -13.072903)
					(end 259.80009 -13.780008)
				)
				(arc
					(start 259.80009 -16.842994)
					(mid 268.372078 -14.777346)
					(end 273.637248 -21.850096)
				)
				(arc
					(start 274.004532 -21.850096)
					(mid 281.437588 -15.350073)
					(end 288.870644 -21.850096)
				)
				(xy 295.900094 -21.850096)
				(arc
					(start 295.900094 -26.566876)
					(mid 302.400117 -33.999932)
					(end 295.900094 -41.432988)
				)
				(xy 295.900094 -46.150022)
				(arc
					(start 288.870644 -46.150022)
					(mid 281.437588 -52.650045)
					(end 274.004532 -46.150022)
				)
				(xy 270.040608 -46.150022)
				(arc
					(start 270.040608 -28.987496)
					(mid 264.695519 -30.242872)
					(end 259.80009 -27.756866)
				)
				(arc
					(start 259.80009 -33.275016)
					(mid 258.921412 -35.396332)
					(end 256.800096 -36.27501)
				)
				(arc
					(start 225.300032 -36.27501)
					(mid 223.178716 -35.396332)
					(end 222.300038 -33.275016)
				)
				(arc
					(start 222.300038 -13.780008)
					(mid 222.007145 -13.072903)
					(end 221.30004 -12.78001)
				)
				(arc
					(start 196.701918 -12.78001)
					(mid 195.939394 -12.681485)
					(end 195.22694 -12.392406)
				)
				(xy 195.22694 -18.130012) (xy 125.586998 -18.130012)
				(arc
					(start 125.586998 -12.386564)
					(mid 124.870167 -12.679944)
					(end 124.102114 -12.78001)
				)
				(arc
					(start 83.70189 -12.78001)
					(mid 82.939366 -12.681485)
					(end 82.226912 -12.392406)
				)
				(xy 82.226912 -12.850114) (xy 12.58697 -12.850114)
				(arc
					(start 12.58697 -12.386564)
					(mid 11.870139 -12.679944)
					(end 11.102086 -12.78001)
				)
				(arc
					(start 1.999996 -12.78001)
					(mid 1.292891 -13.072903)
					(end 0.999998 -13.780008)
				)
				(arc
					(start 0.999998 -17.008602)
					(mid 11.807641 -15.905834)
					(end 13.749528 -26.594816)
				)
				(arc
					(start 13.749528 -26.594816)
					(mid 14.986161 -26.628826)
					(end 16.067024 -27.230578)
				)
				(arc
					(start 17.239742 -28.318968)
					(mid 17.376516 -31.9932)
					(end 13.702284 -32.130238)
				)
				(arc
					(start 12.529566 -31.041848)
					(mid 11.84518 -29.997395)
					(end 11.726672 -28.754324)
				)
				(arc
					(start 11.726672 -28.754324)
					(mid 6.137804 -30.253382)
					(end 0.999998 -27.591512)
				)
				(arc
					(start 0.999998 -46.005242)
					(mid 6.531771 -39.451608)
					(end 14.750034 -36.999926)
				)
				(xy 14.750034 -37.675058) (xy 21.049996 -37.675058)
				(arc
					(start 21.049996 -36.999926)
					(mid 36.05022 -52.00015)
					(end 21.049996 -67.00012)
				)
				(xy 21.049996 -66.324988) (xy 14.750034 -66.324988)
				(arc
					(start 14.750034 -67.00012)
					(mid 6.531776 -64.54843)
					(end 0.999998 -57.994804)
				)
				(arc
					(start 0.999998 -77.671676)
					(mid 1.076099 -78.054261)
					(end 1.29286 -78.378558)
				)
				(arc
					(start 2.121408 -79.207106)
					(mid 2.36089 -79.477285)
					(end 2.566162 -79.774288)
				)
				(xy 34.562542 -79.774288) (xy 34.564574 -59.965082) (xy 55.5625 -59.967114) (xy 55.559452 -79.762604)
				(xy 168.36263 -79.774288) (xy 168.364662 -59.979052) (xy 189.36462 -59.981084) (xy 189.362588 -79.760826)
				(xy 221.861634 -79.764382) (xy 221.855792 -144.763236) (xy 204.455776 -144.763236) (xy 204.453998 -161.282888)
				(xy 183.45404 -161.280602) (xy 183.455818 -144.763236) (xy 40.45585 -144.763236) (xy 40.454072 -161.265616)
				(xy 19.454114 -161.26333) (xy 19.455638 -144.763236)
			)
		)
	)
	(zone
		(layer "F.Cu")
		(hatch none 0.5)
		(connect_pads
			(clearance 0)
		)
		(min_thickness 0.25)
		(keepout
			(tracks allowed)
			(vias allowed)
			(pads allowed)
			(copperpour allowed)
			(footprints allowed)
		)
		(placement
			(enabled no)
			(sheetname "")
		)
		(fill
			(thermal_gap 0.5)
			(thermal_bridge_width 0.5)
			(island_removal_mode 0)
		)
		(polygon
			(pts
				(xy 14.560042 -252.366526) (xy 14.560042 -251.922788) (xy 16.885158 -251.922788) (xy 16.885158 -252.366526)
			)
		)
	)
	(zone
		(layer "F.Cu")
		(hatch none 0.5)
		(connect_pads
			(clearance 0)
		)
		(min_thickness 0.25)
		(keepout
			(tracks allowed)
			(vias allowed)
			(pads allowed)
			(copperpour allowed)
			(footprints allowed)
		)
		(placement
			(enabled no)
			(sheetname "")
		)
		(fill
			(thermal_gap 0.5)
			(thermal_bridge_width 0.5)
			(island_removal_mode 0)
		)
		(polygon
			(pts
				(xy 63.926212 -220.066616) (xy 63.926212 -219.622878) (xy 66.248026 -219.622878) (xy 66.248026 -220.066616)
			)
		)
	)
	(zone
		(layer "F.Cu")
		(hatch none 0.5)
		(connect_pads
			(clearance 0)
		)
		(min_thickness 0.25)
		(keepout
			(tracks allowed)
			(vias allowed)
			(pads allowed)
			(copperpour allowed)
			(footprints allowed)
		)
		(placement
			(enabled no)
			(sheetname "")
		)
		(fill
			(thermal_gap 0.5)
			(thermal_bridge_width 0.5)
			(island_removal_mode 0)
		)
		(polygon
			(pts
				(xy 192.066926 -231.62641) (xy 194.098926 -231.62641) (xy 194.098926 -231.85501) (xy 192.066926 -231.85501)
				(xy 191.930782 -231.85501) (xy 191.883792 -231.85501) (xy 191.883792 -231.62641) (xy 191.930782 -231.62641)
			)
		)
	)
	(zone
		(layer "F.Cu")
		(hatch none 0.5)
		(connect_pads
			(clearance 0)
		)
		(min_thickness 0.25)
		(keepout
			(tracks allowed)
			(vias allowed)
			(pads allowed)
			(copperpour allowed)
			(footprints allowed)
		)
		(placement
			(enabled no)
			(sheetname "")
		)
		(fill
			(thermal_gap 0.5)
			(thermal_bridge_width 0.5)
			(island_removal_mode 0)
		)
		(polygon
			(pts
				(xy 63.977012 -214.96655) (xy 63.977012 -214.522812) (xy 66.186812 -214.522812) (xy 66.186812 -214.96655)
			)
		)
	)
	(zone
		(layer "F.Cu")
		(hatch none 0.5)
		(connect_pads
			(clearance 0)
		)
		(min_thickness 0.25)
		(keepout
			(tracks allowed)
			(vias allowed)
			(pads allowed)
			(copperpour allowed)
			(footprints allowed)
		)
		(placement
			(enabled no)
			(sheetname "")
		)
		(fill
			(thermal_gap 0.5)
			(thermal_bridge_width 0.5)
			(island_removal_mode 0)
		)
		(polygon
			(pts
				(xy 259.056378 -203.916534) (xy 259.056378 -203.472796) (xy 261.381494 -203.472796) (xy 261.381494 -203.916534)
			)
		)
	)
	(zone
		(layer "F.Cu")
		(hatch none 0.5)
		(connect_pads
			(clearance 0)
		)
		(min_thickness 0.25)
		(keepout
			(tracks allowed)
			(vias allowed)
			(pads allowed)
			(copperpour allowed)
			(footprints allowed)
		)
		(placement
			(enabled no)
			(sheetname "")
		)
		(fill
			(thermal_gap 0.5)
			(thermal_bridge_width 0.5)
			(island_removal_mode 0)
		)
		(polygon
			(pts
				(xy 262.50011 -199.666606) (xy 262.50011 -199.222868) (xy 264.825226 -199.222868) (xy 264.825226 -199.666606)
			)
		)
	)
	(zone
		(layer "F.Cu")
		(hatch none 0.5)
		(connect_pads
			(clearance 0)
		)
		(min_thickness 0.25)
		(keepout
			(tracks allowed)
			(vias allowed)
			(pads allowed)
			(copperpour allowed)
			(footprints allowed)
		)
		(placement
			(enabled no)
			(sheetname "")
		)
		(fill
			(thermal_gap 0.5)
			(thermal_bridge_width 0.5)
			(island_removal_mode 0)
		)
		(polygon
			(pts
				(xy 129.63144 -339.369146) (xy 127.88392 -339.369146) (xy 127.88392 -337.433666) (xy 129.63144 -337.433666)
			)
		)
	)
	(zone
		(layer "F.Cu")
		(hatch none 0.5)
		(connect_pads
			(clearance 0)
		)
		(min_thickness 0.25)
		(keepout
			(tracks allowed)
			(vias allowed)
			(pads allowed)
			(copperpour allowed)
			(footprints allowed)
		)
		(placement
			(enabled no)
			(sheetname "")
		)
		(fill
			(thermal_gap 0.5)
			(thermal_bridge_width 0.5)
			(island_removal_mode 0)
		)
		(polygon
			(pts
				(xy 128.887728 -404.802594) (xy 128.887728 -399.959576) (xy 130.772154 -399.959576) (xy 130.772154 -404.802594)
			)
		)
	)
	(zone
		(layer "F.Cu")
		(hatch none 0.5)
		(connect_pads
			(clearance 0)
		)
		(min_thickness 0.25)
		(keepout
			(tracks allowed)
			(vias allowed)
			(pads allowed)
			(copperpour allowed)
			(footprints allowed)
		)
		(placement
			(enabled no)
			(sheetname "")
		)
		(fill
			(thermal_gap 0.5)
			(thermal_bridge_width 0.5)
			(island_removal_mode 0)
		)
		(polygon
			(pts
				(xy 87.50808 -216.047828) (xy 87.7951 -216.047828) (xy 87.82558 -216.017348) (xy 87.82558 -215.389968)
				(xy 87.73922 -215.303608) (xy 87.55126 -215.303608) (xy 87.4776 -215.377268) (xy 87.4776 -216.017348)
			)
		)
	)
	(zone
		(layer "F.Cu")
		(hatch none 0.5)
		(connect_pads
			(clearance 0)
		)
		(min_thickness 0.25)
		(keepout
			(tracks allowed)
			(vias allowed)
			(pads allowed)
			(copperpour allowed)
			(footprints allowed)
		)
		(placement
			(enabled no)
			(sheetname "")
		)
		(fill
			(thermal_gap 0.5)
			(thermal_bridge_width 0.5)
			(island_removal_mode 0)
		)
		(polygon
			(pts
				(xy 405.680926 -197.958202) (xy 405.680926 -197.551802) (xy 407.839926 -197.551802) (xy 407.839926 -197.958202)
			)
		)
	)
	(zone
		(layer "F.Cu")
		(hatch none 0.5)
		(connect_pads
			(clearance 0)
		)
		(min_thickness 0.25)
		(keepout
			(tracks allowed)
			(vias allowed)
			(pads allowed)
			(copperpour allowed)
			(footprints allowed)
		)
		(placement
			(enabled no)
			(sheetname "")
		)
		(fill
			(thermal_gap 0.5)
			(thermal_bridge_width 0.5)
			(island_removal_mode 0)
		)
		(polygon
			(pts
				(xy 41.29151 -312.716418) (xy 41.29151 -312.27268) (xy 43.616626 -312.27268) (xy 43.616626 -312.716418)
			)
		)
	)
	(zone
		(layer "F.Cu")
		(hatch none 0.5)
		(connect_pads
			(clearance 0)
		)
		(min_thickness 0.25)
		(keepout
			(tracks allowed)
			(vias allowed)
			(pads allowed)
			(copperpour allowed)
			(footprints allowed)
		)
		(placement
			(enabled no)
			(sheetname "")
		)
		(fill
			(thermal_gap 0.5)
			(thermal_bridge_width 0.5)
			(island_removal_mode 0)
		)
		(polygon
			(pts
				(xy 262.50011 -247.26646) (xy 262.50011 -246.822722) (xy 264.825226 -246.822722) (xy 264.825226 -247.26646)
			)
		)
	)
	(zone
		(layer "F.Cu")
		(hatch none 0.5)
		(connect_pads
			(clearance 0)
		)
		(min_thickness 0.25)
		(keepout
			(tracks allowed)
			(vias allowed)
			(pads allowed)
			(copperpour allowed)
			(footprints allowed)
		)
		(placement
			(enabled no)
			(sheetname "")
		)
		(fill
			(thermal_gap 0.5)
			(thermal_bridge_width 0.5)
			(island_removal_mode 0)
		)
		(polygon
			(pts
				(xy 328.029062 -404.802594) (xy 328.029062 -399.959576) (xy 329.913488 -399.959576) (xy 329.913488 -404.802594)
			)
		)
	)
	(zone
		(layer "F.Cu")
		(hatch none 0.5)
		(connect_pads
			(clearance 0)
		)
		(min_thickness 0.25)
		(keepout
			(tracks allowed)
			(vias allowed)
			(pads allowed)
			(copperpour allowed)
			(footprints allowed)
		)
		(placement
			(enabled no)
			(sheetname "")
		)
		(fill
			(thermal_gap 0.5)
			(thermal_bridge_width 0.5)
			(island_removal_mode 0)
		)
		(polygon
			(pts
				(xy 307.76291 -286.366458) (xy 307.76291 -285.92272) (xy 310.088026 -285.92272) (xy 310.088026 -286.366458)
			)
		)
	)
	(zone
		(layer "F.Cu")
		(hatch none 0.5)
		(connect_pads
			(clearance 0)
		)
		(min_thickness 0.25)
		(keepout
			(tracks allowed)
			(vias allowed)
			(pads allowed)
			(copperpour allowed)
			(footprints allowed)
		)
		(placement
			(enabled no)
			(sheetname "")
		)
		(fill
			(thermal_gap 0.5)
			(thermal_bridge_width 0.5)
			(island_removal_mode 0)
		)
		(polygon
			(pts
				(xy 274.143978 -201.366628) (xy 274.143978 -200.92289) (xy 276.469094 -200.92289) (xy 276.469094 -201.366628)
			)
		)
	)
	(zone
		(layer "F.Cu")
		(hatch none 0.5)
		(connect_pads
			(clearance 0)
		)
		(min_thickness 0.25)
		(keepout
			(tracks allowed)
			(vias allowed)
			(pads allowed)
			(copperpour allowed)
			(footprints allowed)
		)
		(placement
			(enabled no)
			(sheetname "")
		)
		(fill
			(thermal_gap 0.5)
			(thermal_bridge_width 0.5)
			(island_removal_mode 0)
		)
		(polygon
			(pts
				(xy 262.50011 -271.066514) (xy 262.50011 -270.622776) (xy 264.825226 -270.622776) (xy 264.825226 -271.066514)
			)
		)
	)
	(zone
		(layer "F.Cu")
		(hatch none 0.5)
		(connect_pads
			(clearance 0)
		)
		(min_thickness 0.25)
		(keepout
			(tracks allowed)
			(vias allowed)
			(pads allowed)
			(copperpour allowed)
			(footprints allowed)
		)
		(placement
			(enabled no)
			(sheetname "")
		)
		(fill
			(thermal_gap 0.5)
			(thermal_bridge_width 0.5)
			(island_removal_mode 0)
		)
		(polygon
			(pts
				(xy 63.977012 -213.266528) (xy 63.977012 -212.82279) (xy 66.186812 -212.82279) (xy 66.186812 -213.266528)
			)
		)
	)
	(zone
		(layer "F.Cu")
		(hatch none 0.5)
		(connect_pads
			(clearance 0)
		)
		(min_thickness 0.25)
		(keepout
			(tracks allowed)
			(vias allowed)
			(pads allowed)
			(copperpour allowed)
			(footprints allowed)
		)
		(placement
			(enabled no)
			(sheetname "")
		)
		(fill
			(thermal_gap 0.5)
			(thermal_bridge_width 0.5)
			(island_removal_mode 0)
		)
		(polygon
			(pts
				(xy 59.822842 -289.766502) (xy 59.822842 -289.322764) (xy 62.147958 -289.322764) (xy 62.147958 -289.766502)
			)
		)
	)
	(zone
		(layer "F.Cu")
		(hatch none 0.5)
		(connect_pads
			(clearance 0)
		)
		(min_thickness 0.25)
		(keepout
			(tracks allowed)
			(vias allowed)
			(pads allowed)
			(copperpour allowed)
			(footprints allowed)
		)
		(placement
			(enabled no)
			(sheetname "")
		)
		(fill
			(thermal_gap 0.5)
			(thermal_bridge_width 0.5)
			(island_removal_mode 0)
		)
		(polygon
			(pts
				(xy 292.67531 -283.816552) (xy 292.67531 -283.372814) (xy 295.000426 -283.372814) (xy 295.000426 -283.816552)
			)
		)
	)
	(zone
		(layer "F.Cu")
		(hatch none 0.5)
		(connect_pads
			(clearance 0)
		)
		(min_thickness 0.25)
		(keepout
			(tracks allowed)
			(vias allowed)
			(pads allowed)
			(copperpour allowed)
			(footprints allowed)
		)
		(placement
			(enabled no)
			(sheetname "")
		)
		(fill
			(thermal_gap 0.5)
			(thermal_bridge_width 0.5)
			(island_removal_mode 0)
		)
		(polygon
			(pts
				(xy 18.76298 -386.69214) (xy 18.76298 -384.24358) (xy 20.91944 -384.24358) (xy 20.91944 -386.69214)
			)
		)
	)
	(zone
		(layer "F.Cu")
		(hatch none 0.5)
		(connect_pads
			(clearance 0)
		)
		(min_thickness 0.25)
		(keepout
			(tracks allowed)
			(vias allowed)
			(pads allowed)
			(copperpour allowed)
			(footprints allowed)
		)
		(placement
			(enabled no)
			(sheetname "")
		)
		(fill
			(thermal_gap 0.5)
			(thermal_bridge_width 0.5)
			(island_removal_mode 0)
		)
		(polygon
			(pts
				(xy 44.735242 -217.516456) (xy 44.735242 -217.072718) (xy 47.060358 -217.072718) (xy 47.060358 -217.516456)
			)
		)
	)
	(zone
		(layer "F.Cu")
		(hatch none 0.5)
		(connect_pads
			(clearance 0)
		)
		(min_thickness 0.25)
		(keepout
			(tracks allowed)
			(vias allowed)
			(pads allowed)
			(copperpour allowed)
			(footprints allowed)
		)
		(placement
			(enabled no)
			(sheetname "")
		)
		(fill
			(thermal_gap 0.5)
			(thermal_bridge_width 0.5)
			(island_removal_mode 0)
		)
		(polygon
			(pts
				(xy 311.91708 -216.666572) (xy 311.91708 -216.222834) (xy 314.12688 -216.222834) (xy 314.12688 -216.666572)
			)
		)
	)
	(zone
		(layer "F.Cu")
		(hatch none 0.5)
		(connect_pads
			(clearance 0)
		)
		(min_thickness 0.25)
		(keepout
			(tracks allowed)
			(vias allowed)
			(pads allowed)
			(copperpour allowed)
			(footprints allowed)
		)
		(placement
			(enabled no)
			(sheetname "")
		)
		(fill
			(thermal_gap 0.5)
			(thermal_bridge_width 0.5)
			(island_removal_mode 0)
		)
		(polygon
			(pts
				(xy 154.739848 -410.948886) (xy 154.739848 -406.105868) (xy 156.624274 -406.105868) (xy 156.624274 -410.948886)
			)
		)
	)
	(zone
		(layer "F.Cu")
		(hatch none 0.5)
		(connect_pads
			(clearance 0)
		)
		(min_thickness 0.25)
		(keepout
			(tracks allowed)
			(vias allowed)
			(pads allowed)
			(copperpour allowed)
			(footprints allowed)
		)
		(placement
			(enabled no)
			(sheetname "")
		)
		(fill
			(thermal_gap 0.5)
			(thermal_bridge_width 0.5)
			(island_removal_mode 0)
		)
		(polygon
			(pts
				(xy 180.423058 -203.805028) (xy 180.423058 -203.576428) (xy 182.455058 -203.576428) (xy 182.455058 -203.805028)
			)
		)
	)
	(zone
		(layer "F.Cu")
		(hatch none 0.5)
		(connect_pads
			(clearance 0)
		)
		(min_thickness 0.25)
		(keepout
			(tracks allowed)
			(vias allowed)
			(pads allowed)
			(copperpour allowed)
			(footprints allowed)
		)
		(placement
			(enabled no)
			(sheetname "")
		)
		(fill
			(thermal_gap 0.5)
			(thermal_bridge_width 0.5)
			(island_removal_mode 0)
		)
		(polygon
			(pts
				(xy 210.598258 -297.304968) (xy 210.598258 -297.076368) (xy 212.630258 -297.076368) (xy 212.630258 -297.304968)
			)
		)
	)
	(zone
		(layer "F.Cu")
		(hatch none 0.5)
		(connect_pads
			(clearance 0)
		)
		(min_thickness 0.25)
		(keepout
			(tracks allowed)
			(vias allowed)
			(pads allowed)
			(copperpour allowed)
			(footprints allowed)
		)
		(placement
			(enabled no)
			(sheetname "")
		)
		(fill
			(thermal_gap 0.5)
			(thermal_bridge_width 0.5)
			(island_removal_mode 0)
		)
		(polygon
			(pts
				(xy 26.20391 -280.416508) (xy 26.20391 -279.97277) (xy 28.529026 -279.97277) (xy 28.529026 -280.416508)
			)
		)
	)
	(zone
		(layer "F.Cu")
		(hatch none 0.5)
		(connect_pads
			(clearance 0)
		)
		(min_thickness 0.25)
		(keepout
			(tracks allowed)
			(vias allowed)
			(pads allowed)
			(copperpour allowed)
			(footprints allowed)
		)
		(placement
			(enabled no)
			(sheetname "")
		)
		(fill
			(thermal_gap 0.5)
			(thermal_bridge_width 0.5)
			(island_removal_mode 0)
		)
		(polygon
			(pts
				(xy 455.094594 -249.47626) (xy 457.126594 -249.47626) (xy 457.126594 -249.70486) (xy 455.094594 -249.70486)
				(xy 454.92797 -249.70486) (xy 454.92797 -249.47626)
			)
		)
	)
	(zone
		(layer "F.Cu")
		(hatch none 0.5)
		(connect_pads
			(clearance 0)
		)
		(min_thickness 0.25)
		(keepout
			(tracks allowed)
			(vias allowed)
			(pads allowed)
			(copperpour allowed)
			(footprints not_allowed)
		)
		(placement
			(enabled no)
			(sheetname "")
		)
		(fill
			(thermal_gap 0.5)
			(thermal_bridge_width 0.5)
			(island_removal_mode 0)
		)
		(polygon
			(pts
				(xy 332.629764 -188.770006) (xy 388.13613 -188.770006) (xy 388.13613 -165.970712) (xy 332.629764 -165.970712)
			)
		)
	)
	(zone
		(layer "F.Cu")
		(hatch none 0.5)
		(connect_pads
			(clearance 0)
		)
		(min_thickness 0.25)
		(keepout
			(tracks allowed)
			(vias allowed)
			(pads allowed)
			(copperpour allowed)
			(footprints allowed)
		)
		(placement
			(enabled no)
			(sheetname "")
		)
		(fill
			(thermal_gap 0.5)
			(thermal_bridge_width 0.5)
			(island_removal_mode 0)
		)
		(polygon
			(pts
				(xy 29.647642 -299.116496) (xy 29.647642 -298.672758) (xy 31.972758 -298.672758) (xy 31.972758 -299.116496)
			)
		)
	)
	(zone
		(layer "F.Cu")
		(hatch none 0.5)
		(connect_pads
			(clearance 0)
		)
		(min_thickness 0.25)
		(keepout
			(tracks allowed)
			(vias allowed)
			(pads allowed)
			(copperpour allowed)
			(footprints allowed)
		)
		(placement
			(enabled no)
			(sheetname "")
		)
		(fill
			(thermal_gap 0.5)
			(thermal_bridge_width 0.5)
			(island_removal_mode 0)
		)
		(polygon
			(pts
				(xy 385.37388 -284.137608) (xy 385.6609 -284.137608) (xy 385.69138 -284.107128) (xy 385.69138 -283.479748)
				(xy 385.60502 -283.393388) (xy 385.41706 -283.393388) (xy 385.3434 -283.467048) (xy 385.3434 -284.107128)
			)
		)
	)
	(zone
		(layer "F.Cu")
		(hatch none 0.5)
		(connect_pads
			(clearance 0)
		)
		(min_thickness 0.25)
		(keepout
			(tracks allowed)
			(vias allowed)
			(pads allowed)
			(copperpour allowed)
			(footprints allowed)
		)
		(placement
			(enabled no)
			(sheetname "")
		)
		(fill
			(thermal_gap 0.5)
			(thermal_bridge_width 0.5)
			(island_removal_mode 0)
		)
		(polygon
			(pts
				(xy 428.363126 -280.305002) (xy 428.363126 -280.076402) (xy 430.395126 -280.076402) (xy 430.395126 -280.305002)
			)
		)
	)
	(zone
		(layer "F.Cu")
		(hatch none 0.5)
		(connect_pads
			(clearance 0)
		)
		(min_thickness 0.25)
		(keepout
			(tracks not_allowed)
			(vias allowed)
			(pads allowed)
			(copperpour not_allowed)
			(footprints allowed)
		)
		(placement
			(enabled no)
			(sheetname "")
		)
		(fill
			(thermal_gap 0.5)
			(thermal_bridge_width 0.5)
			(island_removal_mode 0)
		)
		(polygon
			(pts
				(xy 296.429938 -364.393988) (xy 296.672254 -364.393988) (xy 296.672254 -363.548168) (xy 296.429938 -363.548168)
			)
		)
	)
	(zone
		(layer "F.Cu")
		(hatch none 0.5)
		(connect_pads
			(clearance 0)
		)
		(min_thickness 0.25)
		(keepout
			(tracks allowed)
			(vias allowed)
			(pads allowed)
			(copperpour allowed)
			(footprints allowed)
		)
		(placement
			(enabled no)
			(sheetname "")
		)
		(fill
			(thermal_gap 0.5)
			(thermal_bridge_width 0.5)
			(island_removal_mode 0)
		)
		(polygon
			(pts
				(xy 180.423058 -225.904806) (xy 180.423058 -225.676206) (xy 182.455058 -225.676206) (xy 182.455058 -225.904806)
			)
		)
	)
	(zone
		(layer "F.Cu")
		(hatch none 0.5)
		(connect_pads
			(clearance 0)
		)
		(min_thickness 0.25)
		(keepout
			(tracks allowed)
			(vias allowed)
			(pads allowed)
			(copperpour allowed)
			(footprints allowed)
		)
		(placement
			(enabled no)
			(sheetname "")
		)
		(fill
			(thermal_gap 0.5)
			(thermal_bridge_width 0.5)
			(island_removal_mode 0)
		)
		(polygon
			(pts
				(xy 292.67531 -301.666656) (xy 292.67531 -301.222918) (xy 295.000426 -301.222918) (xy 295.000426 -301.666656)
			)
		)
	)
	(zone
		(layer "F.Cu")
		(hatch none 0.5)
		(connect_pads
			(clearance 0)
		)
		(min_thickness 0.25)
		(keepout
			(tracks allowed)
			(vias allowed)
			(pads allowed)
			(copperpour allowed)
			(footprints allowed)
		)
		(placement
			(enabled no)
			(sheetname "")
		)
		(fill
			(thermal_gap 0.5)
			(thermal_bridge_width 0.5)
			(island_removal_mode 0)
		)
		(polygon
			(pts
				(xy 29.647642 -271.472914) (xy 31.972758 -271.472914) (xy 32.041084 -271.472914) (xy 32.041084 -272.406618)
				(xy 29.520388 -272.406618) (xy 29.520388 -271.472914)
			)
		)
	)
	(zone
		(layer "F.Cu")
		(hatch none 0.5)
		(connect_pads
			(clearance 0)
		)
		(min_thickness 0.25)
		(keepout
			(tracks allowed)
			(vias allowed)
			(pads allowed)
			(copperpour allowed)
			(footprints allowed)
		)
		(placement
			(enabled no)
			(sheetname "")
		)
		(fill
			(thermal_gap 0.5)
			(thermal_bridge_width 0.5)
			(island_removal_mode 0)
		)
		(polygon
			(pts
				(xy 292.67531 -280.416508) (xy 292.67531 -279.97277) (xy 295.000426 -279.97277) (xy 295.000426 -280.416508)
			)
		)
	)
	(zone
		(layer "F.Cu")
		(hatch none 0.5)
		(connect_pads
			(clearance 0)
		)
		(min_thickness 0.25)
		(keepout
			(tracks allowed)
			(vias allowed)
			(pads allowed)
			(copperpour allowed)
			(footprints not_allowed)
		)
		(placement
			(enabled no)
			(sheetname "")
		)
		(fill
			(thermal_gap 0.5)
			(thermal_bridge_width 0.5)
			(island_removal_mode 0)
		)
		(polygon
			(pts
				(xy 458.56017 -330.091796) (xy 464.65998 -330.091796) (xy 464.65998 -186.09183) (xy 458.56017 -186.09183)
			)
		)
	)
	(zone
		(layer "F.Cu")
		(hatch none 0.5)
		(connect_pads
			(clearance 0)
		)
		(min_thickness 0.25)
		(keepout
			(tracks allowed)
			(vias allowed)
			(pads allowed)
			(copperpour allowed)
			(footprints allowed)
		)
		(placement
			(enabled no)
			(sheetname "")
		)
		(fill
			(thermal_gap 0.5)
			(thermal_bridge_width 0.5)
			(island_removal_mode 0)
		)
		(polygon
			(pts
				(xy 7.881874 -252.918722) (xy 7.881874 -194.7418) (xy 8.233918 -194.389756) (xy 65.63614 -194.389756)
				(xy 66.360294 -194.389756) (xy 66.64706 -194.676522) (xy 66.64706 -198.184262) (xy 66.41084 -198.420482)
				(xy 66.41084 -202.255882) (xy 66.57086 -202.415902) (xy 66.903092 -202.748134) (xy 66.903092 -203.68133)
				(xy 66.57086 -204.013562) (xy 66.57086 -204.856842) (xy 66.57086 -205.992222) (xy 66.41084 -206.152242)
				(xy 66.41084 -209.149442) (xy 67.11696 -209.855562) (xy 67.11696 -210.018122) (xy 67.11696 -210.998562)
				(xy 66.93916 -211.176362) (xy 66.64452 -211.471002) (xy 66.64452 -221.465902) (xy 66.64452 -222.431102)
				(xy 66.64452 -223.04121) (xy 66.41084 -223.27489) (xy 66.41084 -232.659682) (xy 66.68516 -232.934002)
				(xy 66.80962 -233.058462) (xy 66.80962 -233.896662) (xy 66.78803 -233.918252) (xy 66.78803 -237.450122)
				(xy 67.45986 -238.121952) (xy 67.45986 -239.098582) (xy 67.27444 -239.284002) (xy 66.41084 -240.147602)
				(xy 66.41084 -252.7427) (xy 65.77711 -253.37643) (xy 8.339582 -253.37643)
			)
		)
	)
	(zone
		(layer "F.Cu")
		(hatch none 0.5)
		(connect_pads
			(clearance 0)
		)
		(min_thickness 0.25)
		(keepout
			(tracks allowed)
			(vias allowed)
			(pads allowed)
			(copperpour allowed)
			(footprints allowed)
		)
		(placement
			(enabled no)
			(sheetname "")
		)
		(fill
			(thermal_gap 0.5)
			(thermal_bridge_width 0.5)
			(island_removal_mode 0)
		)
		(polygon
			(pts
				(xy 405.731726 -197.00494) (xy 405.731726 -196.77634) (xy 407.763726 -196.77634) (xy 407.763726 -197.00494)
			)
		)
	)
	(zone
		(layer "F.Cu")
		(hatch none 0.5)
		(connect_pads
			(clearance 0)
		)
		(min_thickness 0.25)
		(keepout
			(tracks allowed)
			(vias allowed)
			(pads allowed)
			(copperpour allowed)
			(footprints allowed)
		)
		(placement
			(enabled no)
			(sheetname "")
		)
		(fill
			(thermal_gap 0.5)
			(thermal_bridge_width 0.5)
			(island_removal_mode 0)
		)
		(polygon
			(pts
				(xy 80.77454 -150.025608) (xy 80.77454 -145.166588) (xy 83.21802 -145.166588) (xy 83.21802 -150.025608)
			)
		)
	)
	(zone
		(layer "F.Cu")
		(hatch none 0.5)
		(connect_pads
			(clearance 0)
		)
		(min_thickness 0.25)
		(keepout
			(tracks allowed)
			(vias allowed)
			(pads allowed)
			(copperpour allowed)
			(footprints not_allowed)
		)
		(placement
			(enabled no)
			(sheetname "")
		)
		(fill
			(thermal_gap 0.5)
			(thermal_bridge_width 0.5)
			(island_removal_mode 0)
		)
		(polygon
			(pts
				(xy 50.88001 -52.55006) (xy 76.630022 -52.55006) (xy 76.63307 -41.550082) (xy 50.88001 -41.550082)
			)
		)
	)
	(zone
		(layer "F.Cu")
		(hatch none 0.5)
		(connect_pads
			(clearance 0)
		)
		(min_thickness 0.25)
		(keepout
			(tracks allowed)
			(vias allowed)
			(pads allowed)
			(copperpour allowed)
			(footprints allowed)
		)
		(placement
			(enabled no)
			(sheetname "")
		)
		(fill
			(thermal_gap 0.5)
			(thermal_bridge_width 0.5)
			(island_removal_mode 0)
		)
		(polygon
			(pts
				(xy 44.735242 -299.116496) (xy 44.735242 -298.672758) (xy 47.060358 -298.672758) (xy 47.060358 -299.116496)
			)
		)
	)
	(zone
		(layer "F.Cu")
		(hatch none 0.5)
		(connect_pads
			(clearance 0)
		)
		(min_thickness 0.25)
		(keepout
			(tracks allowed)
			(vias allowed)
			(pads allowed)
			(copperpour allowed)
			(footprints allowed)
		)
		(placement
			(enabled no)
			(sheetname "")
		)
		(fill
			(thermal_gap 0.5)
			(thermal_bridge_width 0.5)
			(island_removal_mode 0)
		)
		(polygon
			(pts
				(xy 405.731726 -275.826474) (xy 407.763726 -275.826474) (xy 407.763726 -275.82876) (xy 407.942542 -275.82876)
				(xy 407.942542 -276.065996) (xy 408.080464 -276.065996) (xy 408.123644 -276.109176) (xy 408.123644 -276.242018)
				(xy 408.123644 -276.546056) (xy 408.051 -276.6187) (xy 405.510746 -276.6187) (xy 405.369522 -276.477476)
				(xy 405.369522 -276.280372) (xy 405.451056 -276.198838) (xy 405.451056 -275.826474) (xy 405.548592 -275.826474)
				(xy 405.595582 -275.826474)
			)
		)
	)
	(zone
		(layer "F.Cu")
		(hatch none 0.5)
		(connect_pads
			(clearance 0)
		)
		(min_thickness 0.25)
		(keepout
			(tracks allowed)
			(vias allowed)
			(pads allowed)
			(copperpour allowed)
			(footprints allowed)
		)
		(placement
			(enabled no)
			(sheetname "")
		)
		(fill
			(thermal_gap 0.5)
			(thermal_bridge_width 0.5)
			(island_removal_mode 0)
		)
		(polygon
			(pts
				(xy 161.891726 -293.904924) (xy 161.891726 -293.676324) (xy 163.923726 -293.676324) (xy 163.923726 -293.904924)
			)
		)
	)
	(zone
		(layer "F.Cu")
		(hatch none 0.5)
		(connect_pads
			(clearance 0)
		)
		(min_thickness 0.25)
		(keepout
			(tracks allowed)
			(vias allowed)
			(pads allowed)
			(copperpour allowed)
			(footprints allowed)
		)
		(placement
			(enabled no)
			(sheetname "")
		)
		(fill
			(thermal_gap 0.5)
			(thermal_bridge_width 0.5)
			(island_removal_mode 0)
		)
		(polygon
			(pts
				(xy 405.731726 -295.604946) (xy 405.731726 -295.376346) (xy 407.763726 -295.376346) (xy 407.763726 -295.604946)
			)
		)
	)
	(zone
		(layer "F.Cu")
		(hatch none 0.5)
		(connect_pads
			(clearance 0)
		)
		(min_thickness 0.25)
		(keepout
			(tracks allowed)
			(vias allowed)
			(pads allowed)
			(copperpour allowed)
			(footprints allowed)
		)
		(placement
			(enabled no)
			(sheetname "")
		)
		(fill
			(thermal_gap 0.5)
			(thermal_bridge_width 0.5)
			(island_removal_mode 0)
		)
		(polygon
			(pts
				(xy 311.91708 -264.266426) (xy 311.91708 -263.822688) (xy 314.15228 -263.822688) (xy 314.15228 -264.266426)
			)
		)
	)
	(zone
		(layer "F.Cu")
		(hatch none 0.5)
		(connect_pads
			(clearance 0)
		)
		(min_thickness 0.25)
		(keepout
			(tracks allowed)
			(vias allowed)
			(pads allowed)
			(copperpour allowed)
			(footprints allowed)
		)
		(placement
			(enabled no)
			(sheetname "")
		)
		(fill
			(thermal_gap 0.5)
			(thermal_bridge_width 0.5)
			(island_removal_mode 0)
		)
		(polygon
			(pts
				(xy 157.823154 -247.154954) (xy 157.823154 -246.926354) (xy 159.778954 -246.926354) (xy 159.778954 -247.154954)
			)
		)
	)
	(zone
		(layer "F.Cu")
		(hatch none 0.5)
		(connect_pads
			(clearance 0)
		)
		(min_thickness 0.25)
		(keepout
			(tracks allowed)
			(vias allowed)
			(pads allowed)
			(copperpour allowed)
			(footprints allowed)
		)
		(placement
			(enabled no)
			(sheetname "")
		)
		(fill
			(thermal_gap 0.5)
			(thermal_bridge_width 0.5)
			(island_removal_mode 0)
		)
		(polygon
			(pts
				(xy 413.275526 -308.354984) (xy 413.275526 -308.126384) (xy 415.307526 -308.126384) (xy 415.307526 -308.354984)
			)
		)
	)
	(zone
		(layer "F.Cu")
		(hatch none 0.5)
		(connect_pads
			(clearance 0)
		)
		(min_thickness 0.25)
		(keepout
			(tracks allowed)
			(vias allowed)
			(pads allowed)
			(copperpour allowed)
			(footprints allowed)
		)
		(placement
			(enabled no)
			(sheetname "")
		)
		(fill
			(thermal_gap 0.5)
			(thermal_bridge_width 0.5)
			(island_removal_mode 0)
		)
		(polygon
			(pts
				(xy 59.822842 -203.916534) (xy 59.822842 -203.472796) (xy 62.147958 -203.472796) (xy 62.147958 -203.916534)
			)
		)
	)
	(zone
		(layer "F.Cu")
		(hatch none 0.5)
		(connect_pads
			(clearance 0)
		)
		(min_thickness 0.25)
		(keepout
			(tracks allowed)
			(vias allowed)
			(pads allowed)
			(copperpour allowed)
			(footprints allowed)
		)
		(placement
			(enabled no)
			(sheetname "")
		)
		(fill
			(thermal_gap 0.5)
			(thermal_bridge_width 0.5)
			(island_removal_mode 0)
		)
		(polygon
			(pts
				(xy 289.231578 -275.316442) (xy 289.231578 -274.872704) (xy 291.556694 -274.872704) (xy 291.556694 -275.316442)
			)
		)
	)
	(zone
		(layer "F.Cu")
		(hatch none 0.5)
		(connect_pads
			(clearance 0)
		)
		(min_thickness 0.25)
		(keepout
			(tracks allowed)
			(vias allowed)
			(pads allowed)
			(copperpour allowed)
			(footprints allowed)
		)
		(placement
			(enabled no)
			(sheetname "")
		)
		(fill
			(thermal_gap 0.5)
			(thermal_bridge_width 0.5)
			(island_removal_mode 0)
		)
		(polygon
			(pts
				(xy 230.43642 -404.41372) (xy 230.43642 -401.066) (xy 233.81716 -401.066) (xy 233.81716 -404.41372)
			)
		)
	)
	(zone
		(layer "F.Cu")
		(hatch none 0.5)
		(connect_pads
			(clearance 0)
		)
		(min_thickness 0.25)
		(keepout
			(tracks allowed)
			(vias allowed)
			(pads allowed)
			(copperpour allowed)
			(footprints allowed)
		)
		(placement
			(enabled no)
			(sheetname "")
		)
		(fill
			(thermal_gap 0.5)
			(thermal_bridge_width 0.5)
			(island_removal_mode 0)
		)
		(polygon
			(pts
				(xy 195.510658 -316.004956) (xy 195.510658 -315.776356) (xy 197.542658 -315.776356) (xy 197.542658 -316.004956)
			)
		)
	)
	(zone
		(layer "F.Cu")
		(hatch none 0.5)
		(connect_pads
			(clearance 0)
		)
		(min_thickness 0.25)
		(keepout
			(tracks allowed)
			(vias allowed)
			(pads allowed)
			(copperpour allowed)
			(footprints allowed)
		)
		(placement
			(enabled no)
			(sheetname "")
		)
		(fill
			(thermal_gap 0.5)
			(thermal_bridge_width 0.5)
			(island_removal_mode 0)
		)
		(polygon
			(pts
				(xy 336.01152 -288.277808) (xy 336.29854 -288.277808) (xy 336.32902 -288.247328) (xy 336.32902 -287.619948)
				(xy 336.24266 -287.533588) (xy 336.0547 -287.533588) (xy 335.98104 -287.607248) (xy 335.98104 -288.247328)
			)
		)
	)
	(zone
		(layer "F.Cu")
		(hatch none 0.5)
		(connect_pads
			(clearance 0)
		)
		(min_thickness 0.25)
		(keepout
			(tracks allowed)
			(vias allowed)
			(pads allowed)
			(copperpour allowed)
			(footprints allowed)
		)
		(placement
			(enabled no)
			(sheetname "")
		)
		(fill
			(thermal_gap 0.5)
			(thermal_bridge_width 0.5)
			(island_removal_mode 0)
		)
		(polygon
			(pts
				(xy 59.822842 -268.516608) (xy 59.822842 -268.07287) (xy 62.097412 -268.07287) (xy 62.097412 -268.516608)
			)
		)
	)
	(zone
		(layer "F.Cu")
		(hatch none 0.5)
		(connect_pads
			(clearance 0)
		)
		(min_thickness 0.25)
		(keepout
			(tracks allowed)
			(vias allowed)
			(pads allowed)
			(copperpour allowed)
			(footprints allowed)
		)
		(placement
			(enabled no)
			(sheetname "")
		)
		(fill
			(thermal_gap 0.5)
			(thermal_bridge_width 0.5)
			(island_removal_mode 0)
		)
		(polygon
			(pts
				(xy 192.066926 -233.326432) (xy 194.098926 -233.326432) (xy 194.098926 -233.328718) (xy 194.277742 -233.328718)
				(xy 194.277742 -233.565954) (xy 194.415664 -233.565954) (xy 194.458844 -233.609134) (xy 194.458844 -233.741976)
				(xy 194.458844 -234.046014) (xy 194.3862 -234.118658) (xy 191.845946 -234.118658) (xy 191.704722 -233.977434)
				(xy 191.704722 -233.78033) (xy 191.786256 -233.698796) (xy 191.786256 -233.326432) (xy 191.883792 -233.326432)
				(xy 191.930782 -233.326432)
			)
		)
	)
	(zone
		(layer "F.Cu")
		(hatch none 0.5)
		(connect_pads
			(clearance 0)
		)
		(min_thickness 0.25)
		(keepout
			(tracks allowed)
			(vias allowed)
			(pads allowed)
			(copperpour allowed)
			(footprints allowed)
		)
		(placement
			(enabled no)
			(sheetname "")
		)
		(fill
			(thermal_gap 0.5)
			(thermal_bridge_width 0.5)
			(island_removal_mode 0)
		)
		(polygon
			(pts
				(xy 409.831794 -287.954974) (xy 409.831794 -287.726374) (xy 411.863794 -287.726374) (xy 411.863794 -287.954974)
			)
		)
	)
	(zone
		(layer "F.Cu")
		(hatch none 0.5)
		(connect_pads
			(clearance 0)
		)
		(min_thickness 0.25)
		(keepout
			(tracks allowed)
			(vias allowed)
			(pads allowed)
			(copperpour allowed)
			(footprints allowed)
		)
		(placement
			(enabled no)
			(sheetname "")
		)
		(fill
			(thermal_gap 0.5)
			(thermal_bridge_width 0.5)
			(island_removal_mode 0)
		)
		(polygon
			(pts
				(xy 11.11631 -314.41644) (xy 11.11631 -313.972702) (xy 13.441426 -313.972702) (xy 13.441426 -314.41644)
			)
		)
	)
	(zone
		(layer "F.Cu")
		(hatch none 0.5)
		(connect_pads
			(clearance 0)
		)
		(min_thickness 0.25)
		(keepout
			(tracks allowed)
			(vias allowed)
			(pads allowed)
			(copperpour allowed)
			(footprints allowed)
		)
		(placement
			(enabled no)
			(sheetname "")
		)
		(fill
			(thermal_gap 0.5)
			(thermal_bridge_width 0.5)
			(island_removal_mode 0)
		)
		(polygon
			(pts
				(xy 119.27332 -321.346068) (xy 119.27332 -319.060068) (xy 123.73356 -319.060068) (xy 123.73356 -321.346068)
			)
		)
	)
	(zone
		(layer "F.Cu")
		(hatch none 0.5)
		(connect_pads
			(clearance 0)
		)
		(min_thickness 0.25)
		(keepout
			(tracks allowed)
			(vias allowed)
			(pads allowed)
			(copperpour allowed)
			(footprints allowed)
		)
		(placement
			(enabled no)
			(sheetname "")
		)
		(fill
			(thermal_gap 0.5)
			(thermal_bridge_width 0.5)
			(island_removal_mode 0)
		)
		(polygon
			(pts
				(xy 165.335458 -269.254986) (xy 165.335458 -269.026386) (xy 167.367458 -269.026386) (xy 167.367458 -269.254986)
			)
		)
	)
	(zone
		(layer "F.Cu")
		(hatch none 0.5)
		(connect_pads
			(clearance 0)
		)
		(min_thickness 0.25)
		(keepout
			(tracks allowed)
			(vias allowed)
			(pads allowed)
			(copperpour allowed)
			(footprints not_allowed)
		)
		(placement
			(enabled no)
			(sheetname "")
		)
		(fill
			(thermal_gap 0.5)
			(thermal_bridge_width 0.5)
			(island_removal_mode 0)
		)
		(polygon
			(pts
				(xy 356.059994 -262.115046) (xy 356.059994 -236.514894) (xy 351.460054 -236.514894) (xy 351.460054 -262.115046)
			)
		)
	)
	(zone
		(layer "F.Cu")
		(hatch none 0.5)
		(connect_pads
			(clearance 0)
		)
		(min_thickness 0.25)
		(keepout
			(tracks allowed)
			(vias allowed)
			(pads allowed)
			(copperpour allowed)
			(footprints allowed)
		)
		(placement
			(enabled no)
			(sheetname "")
		)
		(fill
			(thermal_gap 0.5)
			(thermal_bridge_width 0.5)
			(island_removal_mode 0)
		)
		(polygon
			(pts
				(xy 26.20391 -310.166512) (xy 26.20391 -309.722774) (xy 28.529026 -309.722774) (xy 28.529026 -310.166512)
			)
		)
	)
	(zone
		(layer "F.Cu")
		(hatch none 0.5)
		(connect_pads
			(clearance 0)
		)
		(min_thickness 0.25)
		(keepout
			(tracks allowed)
			(vias allowed)
			(pads allowed)
			(copperpour allowed)
			(footprints allowed)
		)
		(placement
			(enabled no)
			(sheetname "")
		)
		(fill
			(thermal_gap 0.5)
			(thermal_bridge_width 0.5)
			(island_removal_mode 0)
		)
		(polygon
			(pts
				(xy 310.088026 -239.616488) (xy 307.76291 -239.616488) (xy 307.455316 -239.616488) (xy 307.455316 -238.641382)
				(xy 310.366918 -238.641382) (xy 310.366918 -239.616488)
			)
		)
	)
	(zone
		(layer "F.Cu")
		(hatch none 0.5)
		(connect_pads
			(clearance 0)
		)
		(min_thickness 0.25)
		(keepout
			(tracks allowed)
			(vias allowed)
			(pads allowed)
			(copperpour allowed)
			(footprints allowed)
		)
		(placement
			(enabled no)
			(sheetname "")
		)
		(fill
			(thermal_gap 0.5)
			(thermal_bridge_width 0.5)
			(island_removal_mode 0)
		)
		(polygon
			(pts
				(xy 63.951612 -268.516608) (xy 63.951612 -268.07287) (xy 66.186812 -268.07287) (xy 66.412872 -268.07287)
				(xy 66.412872 -268.915642) (xy 63.951612 -268.915642)
			)
		)
	)
	(zone
		(layer "F.Cu")
		(hatch none 0.5)
		(connect_pads
			(clearance 0)
		)
		(min_thickness 0.25)
		(keepout
			(tracks allowed)
			(vias allowed)
			(pads allowed)
			(copperpour allowed)
			(footprints allowed)
		)
		(placement
			(enabled no)
			(sheetname "")
		)
		(fill
			(thermal_gap 0.5)
			(thermal_bridge_width 0.5)
			(island_removal_mode 0)
		)
		(polygon
			(pts
				(xy 131.950968 -404.802594) (xy 131.950968 -399.959576) (xy 133.835394 -399.959576) (xy 133.835394 -404.802594)
			)
		)
	)
	(zone
		(layer "F.Cu")
		(hatch none 0.5)
		(connect_pads
			(clearance 0)
		)
		(min_thickness 0.25)
		(keepout
			(tracks allowed)
			(vias allowed)
			(pads allowed)
			(copperpour allowed)
			(footprints allowed)
		)
		(placement
			(enabled no)
			(sheetname "")
		)
		(fill
			(thermal_gap 0.5)
			(thermal_bridge_width 0.5)
			(island_removal_mode 0)
		)
		(polygon
			(pts
				(xy 277.58771 -292.316662) (xy 277.58771 -291.872924) (xy 279.912826 -291.872924) (xy 279.912826 -292.316662)
			)
		)
	)
	(zone
		(layer "F.Cu")
		(hatch none 0.5)
		(connect_pads
			(clearance 0)
		)
		(min_thickness 0.25)
		(keepout
			(tracks allowed)
			(vias allowed)
			(pads allowed)
			(copperpour allowed)
			(footprints allowed)
		)
		(placement
			(enabled no)
			(sheetname "")
		)
		(fill
			(thermal_gap 0.5)
			(thermal_bridge_width 0.5)
			(island_removal_mode 0)
		)
		(polygon
			(pts
				(xy 31.972758 -271.066514) (xy 29.647642 -271.066514) (xy 29.516324 -271.066514) (xy 29.516324 -270.132556)
				(xy 32.028892 -270.132556) (xy 32.028892 -271.066514)
			)
		)
	)
	(zone
		(layer "F.Cu")
		(hatch none 0.5)
		(connect_pads
			(clearance 0)
		)
		(min_thickness 0.25)
		(keepout
			(tracks allowed)
			(vias allowed)
			(pads allowed)
			(copperpour allowed)
			(footprints not_allowed)
		)
		(placement
			(enabled no)
			(sheetname "")
		)
		(fill
			(thermal_gap 0.5)
			(thermal_bridge_width 0.5)
			(island_removal_mode 0)
		)
		(polygon
			(pts
				(xy 405.75357 -330.091796) (xy 411.85338 -330.091796) (xy 411.85338 -186.09183) (xy 405.75357 -186.09183)
			)
		)
	)
	(zone
		(layer "F.Cu")
		(hatch none 0.5)
		(connect_pads
			(clearance 0)
		)
		(min_thickness 0.25)
		(keepout
			(tracks allowed)
			(vias allowed)
			(pads allowed)
			(copperpour allowed)
			(footprints allowed)
		)
		(placement
			(enabled no)
			(sheetname "")
		)
		(fill
			(thermal_gap 0.5)
			(thermal_bridge_width 0.5)
			(island_removal_mode 0)
		)
		(polygon
			(pts
				(xy 63.900812 -234.922822) (xy 66.237612 -234.922822) (xy 66.533776 -234.922822) (xy 66.533776 -235.848652)
				(xy 63.578232 -235.848652) (xy 63.578232 -234.922822)
			)
		)
	)
	(zone
		(layer "F.Cu")
		(hatch none 0.5)
		(connect_pads
			(clearance 0)
		)
		(min_thickness 0.25)
		(keepout
			(tracks allowed)
			(vias allowed)
			(pads allowed)
			(copperpour allowed)
			(footprints allowed)
		)
		(placement
			(enabled no)
			(sheetname "")
		)
		(fill
			(thermal_gap 0.5)
			(thermal_bridge_width 0.5)
			(island_removal_mode 0)
		)
		(polygon
			(pts
				(xy 157.791658 -289.654996) (xy 157.791658 -289.426396) (xy 159.823658 -289.426396) (xy 159.823658 -289.654996)
			)
		)
	)
	(zone
		(layer "F.Cu")
		(hatch none 0.5)
		(connect_pads
			(clearance 0)
		)
		(min_thickness 0.25)
		(keepout
			(tracks allowed)
			(vias allowed)
			(pads allowed)
			(copperpour allowed)
			(footprints allowed)
		)
		(placement
			(enabled no)
			(sheetname "")
		)
		(fill
			(thermal_gap 0.5)
			(thermal_bridge_width 0.5)
			(island_removal_mode 0)
		)
		(polygon
			(pts
				(xy 458.538326 -230.154988) (xy 458.538326 -229.926388) (xy 460.570326 -229.926388) (xy 460.570326 -230.154988)
			)
		)
	)
	(zone
		(layer "F.Cu")
		(hatch none 0.5)
		(connect_pads
			(clearance 0)
		)
		(min_thickness 0.25)
		(keepout
			(tracks allowed)
			(vias allowed)
			(pads allowed)
			(copperpour allowed)
			(footprints allowed)
		)
		(placement
			(enabled no)
			(sheetname "")
		)
		(fill
			(thermal_gap 0.5)
			(thermal_bridge_width 0.5)
			(island_removal_mode 0)
		)
		(polygon
			(pts
				(xy 207.154526 -294.526208) (xy 209.186526 -294.526208) (xy 209.186526 -294.754808) (xy 207.154526 -294.754808)
				(xy 207.023208 -294.754808) (xy 206.9973 -294.754808) (xy 206.9973 -294.526208) (xy 207.023208 -294.526208)
			)
		)
	)
	(zone
		(layer "F.Cu")
		(hatch none 0.5)
		(connect_pads
			(clearance 0)
		)
		(min_thickness 0.25)
		(keepout
			(tracks allowed)
			(vias allowed)
			(pads allowed)
			(copperpour allowed)
			(footprints allowed)
		)
		(placement
			(enabled no)
			(sheetname "")
		)
		(fill
			(thermal_gap 0.5)
			(thermal_bridge_width 0.5)
			(island_removal_mode 0)
		)
		(polygon
			(pts
				(xy 44.735242 -305.916584) (xy 44.735242 -305.472846) (xy 47.060358 -305.472846) (xy 47.060358 -305.916584)
			)
		)
	)
	(zone
		(layer "F.Cu")
		(hatch none 0.5)
		(connect_pads
			(clearance 0)
		)
		(min_thickness 0.25)
		(keepout
			(tracks allowed)
			(vias allowed)
			(pads allowed)
			(copperpour allowed)
			(footprints allowed)
		)
		(placement
			(enabled no)
			(sheetname "")
		)
		(fill
			(thermal_gap 0.5)
			(thermal_bridge_width 0.5)
			(island_removal_mode 0)
		)
		(polygon
			(pts
				(xy 70.311772 -410.948886) (xy 70.311772 -406.105868) (xy 72.196198 -406.105868) (xy 72.196198 -410.948886)
			)
		)
	)
	(zone
		(layer "F.Cu")
		(hatch none 0.5)
		(connect_pads
			(clearance 0)
		)
		(min_thickness 0.25)
		(keepout
			(tracks allowed)
			(vias allowed)
			(pads allowed)
			(copperpour allowed)
			(footprints not_allowed)
		)
		(placement
			(enabled no)
			(sheetname "")
		)
		(fill
			(thermal_gap 0.5)
			(thermal_bridge_width 0.5)
			(island_removal_mode 0)
		)
		(polygon
			(pts
				(xy 94.128336 -14.780006) (xy 94.128336 -6.780022) (xy 105.128314 -6.780022) (xy 105.128314 -14.780006)
			)
		)
	)
	(zone
		(layer "F.Cu")
		(hatch none 0.5)
		(connect_pads
			(clearance 0)
		)
		(min_thickness 0.25)
		(keepout
			(tracks allowed)
			(vias allowed)
			(pads allowed)
			(copperpour allowed)
			(footprints allowed)
		)
		(placement
			(enabled no)
			(sheetname "")
		)
		(fill
			(thermal_gap 0.5)
			(thermal_bridge_width 0.5)
			(island_removal_mode 0)
		)
		(polygon
			(pts
				(xy 429.352202 -5.888228) (xy 429.352202 -3.952748) (xy 431.523902 -3.952748) (xy 431.523902 -5.888228)
			)
		)
	)
	(zone
		(layer "F.Cu")
		(hatch none 0.5)
		(connect_pads
			(clearance 0)
		)
		(min_thickness 0.25)
		(keepout
			(tracks allowed)
			(vias allowed)
			(pads allowed)
			(copperpour allowed)
			(footprints not_allowed)
		)
		(placement
			(enabled no)
			(sheetname "")
		)
		(fill
			(thermal_gap 0.5)
			(thermal_bridge_width 0.5)
			(island_removal_mode 0)
		)
		(polygon
			(pts
				(xy 244.879876 -374.753886) (xy 270.47825 -374.753886) (xy 270.480282 -350.763586) (xy 244.879876 -350.763586)
			)
		)
	)
	(zone
		(layer "F.Cu")
		(hatch none 0.5)
		(connect_pads
			(clearance 0)
		)
		(min_thickness 0.25)
		(keepout
			(tracks allowed)
			(vias allowed)
			(pads allowed)
			(copperpour allowed)
			(footprints allowed)
		)
		(placement
			(enabled no)
			(sheetname "")
		)
		(fill
			(thermal_gap 0.5)
			(thermal_bridge_width 0.5)
			(island_removal_mode 0)
		)
		(polygon
			(pts
				(xy 307.76291 -305.916584) (xy 307.76291 -305.472846) (xy 310.088026 -305.472846) (xy 310.088026 -305.916584)
			)
		)
	)
	(zone
		(layer "F.Cu")
		(hatch none 0.5)
		(connect_pads
			(clearance 0)
		)
		(min_thickness 0.25)
		(keepout
			(tracks allowed)
			(vias allowed)
			(pads allowed)
			(copperpour allowed)
			(footprints allowed)
		)
		(placement
			(enabled no)
			(sheetname "")
		)
		(fill
			(thermal_gap 0.5)
			(thermal_bridge_width 0.5)
			(island_removal_mode 0)
		)
		(polygon
			(pts
				(xy 121.044208 -410.948886) (xy 121.044208 -406.105868) (xy 122.928634 -406.105868) (xy 122.928634 -410.948886)
			)
		)
	)
	(zone
		(layer "F.Cu")
		(hatch none 0.5)
		(connect_pads
			(clearance 0)
		)
		(min_thickness 0.25)
		(keepout
			(tracks allowed)
			(vias allowed)
			(pads allowed)
			(copperpour allowed)
			(footprints allowed)
		)
		(placement
			(enabled no)
			(sheetname "")
		)
		(fill
			(thermal_gap 0.5)
			(thermal_bridge_width 0.5)
			(island_removal_mode 0)
		)
		(polygon
			(pts
				(xy 176.979326 -266.476226) (xy 179.011326 -266.476226) (xy 179.011326 -266.704826) (xy 176.979326 -266.704826)
				(xy 176.812702 -266.704826) (xy 176.812702 -266.476226)
			)
		)
	)
	(zone
		(layer "F.Cu")
		(hatch none 0.5)
		(connect_pads
			(clearance 0)
		)
		(min_thickness 0.25)
		(keepout
			(tracks allowed)
			(vias allowed)
			(pads allowed)
			(copperpour allowed)
			(footprints allowed)
		)
		(placement
			(enabled no)
			(sheetname "")
		)
		(fill
			(thermal_gap 0.5)
			(thermal_bridge_width 0.5)
			(island_removal_mode 0)
		)
		(polygon
			(pts
				(xy 457.126594 -269.026386) (xy 457.126594 -269.254986) (xy 457.256896 -269.254986) (xy 457.256896 -269.66164)
				(xy 454.890378 -269.66164) (xy 454.890378 -268.551152) (xy 457.126594 -268.551152)
			)
		)
	)
	(zone
		(layer "F.Cu")
		(hatch none 0.5)
		(connect_pads
			(clearance 0)
		)
		(min_thickness 0.25)
		(keepout
			(tracks allowed)
			(vias allowed)
			(pads allowed)
			(copperpour allowed)
			(footprints allowed)
		)
		(placement
			(enabled no)
			(sheetname "")
		)
		(fill
			(thermal_gap 0.5)
			(thermal_bridge_width 0.5)
			(island_removal_mode 0)
		)
		(polygon
			(pts
				(xy 59.822842 -283.816552) (xy 59.822842 -283.372814) (xy 62.147958 -283.372814) (xy 62.147958 -283.816552)
			)
		)
	)
	(zone
		(layer "F.Cu")
		(hatch none 0.5)
		(connect_pads
			(clearance 0)
		)
		(min_thickness 0.25)
		(keepout
			(tracks allowed)
			(vias allowed)
			(pads allowed)
			(copperpour allowed)
			(footprints allowed)
		)
		(placement
			(enabled no)
			(sheetname "")
		)
		(fill
			(thermal_gap 0.5)
			(thermal_bridge_width 0.5)
			(island_removal_mode 0)
		)
		(polygon
			(pts
				(xy 157.532578 -317.201296) (xy 157.532578 -316.972696) (xy 159.564578 -316.972696) (xy 159.564578 -317.201296)
			)
		)
	)
	(zone
		(layer "F.Cu")
		(hatch none 0.5)
		(connect_pads
			(clearance 0)
		)
		(min_thickness 0.25)
		(keepout
			(tracks allowed)
			(vias allowed)
			(pads allowed)
			(copperpour allowed)
			(footprints allowed)
		)
		(placement
			(enabled no)
			(sheetname "")
		)
		(fill
			(thermal_gap 0.5)
			(thermal_bridge_width 0.5)
			(island_removal_mode 0)
		)
		(polygon
			(pts
				(xy 26.20391 -231.966516) (xy 26.20391 -231.522778) (xy 28.529026 -231.522778) (xy 28.529026 -231.966516)
			)
		)
	)
	(zone
		(layer "F.Cu")
		(hatch none 0.5)
		(connect_pads
			(clearance 0)
		)
		(min_thickness 0.25)
		(keepout
			(tracks allowed)
			(vias allowed)
			(pads allowed)
			(copperpour allowed)
			(footprints allowed)
		)
		(placement
			(enabled no)
			(sheetname "")
		)
		(fill
			(thermal_gap 0.5)
			(thermal_bridge_width 0.5)
			(island_removal_mode 0)
		)
		(polygon
			(pts
				(xy 458.538326 -274.354798) (xy 458.538326 -274.126198) (xy 460.570326 -274.126198) (xy 460.570326 -274.354798)
			)
		)
	)
	(zone
		(layer "F.Cu")
		(hatch none 0.5)
		(connect_pads
			(clearance 0)
		)
		(min_thickness 0.25)
		(keepout
			(tracks allowed)
			(vias allowed)
			(pads allowed)
			(copperpour allowed)
			(footprints allowed)
		)
		(placement
			(enabled no)
			(sheetname "")
		)
		(fill
			(thermal_gap 0.5)
			(thermal_bridge_width 0.5)
			(island_removal_mode 0)
		)
		(polygon
			(pts
				(xy 128.75514 -336.318606) (xy 126.93904 -336.318606) (xy 126.93904 -334.939386) (xy 128.75514 -334.939386)
			)
		)
	)
	(zone
		(layer "F.Cu")
		(hatch none 0.5)
		(connect_pads
			(clearance 0)
		)
		(min_thickness 0.25)
		(keepout
			(tracks allowed)
			(vias allowed)
			(pads allowed)
			(copperpour allowed)
			(footprints allowed)
		)
		(placement
			(enabled no)
			(sheetname "")
		)
		(fill
			(thermal_gap 0.5)
			(thermal_bridge_width 0.5)
			(island_removal_mode 0)
		)
		(polygon
			(pts
				(xy 28.529026 -276.16658) (xy 26.20391 -276.16658) (xy 26.074116 -276.16658) (xy 26.074116 -274.963636)
				(xy 28.594812 -274.963636) (xy 28.594812 -276.16658)
			)
		)
	)
	(zone
		(layer "F.Cu")
		(hatch none 0.5)
		(connect_pads
			(clearance 0)
		)
		(min_thickness 0.25)
		(keepout
			(tracks allowed)
			(vias allowed)
			(pads allowed)
			(copperpour allowed)
			(footprints allowed)
		)
		(placement
			(enabled no)
			(sheetname "")
		)
		(fill
			(thermal_gap 0.5)
			(thermal_bridge_width 0.5)
			(island_removal_mode 0)
		)
		(polygon
			(pts
				(xy 347.97746 -339.418168) (xy 347.97746 -334.322928) (xy 354.29698 -334.322928) (xy 354.29698 -339.418168)
			)
		)
	)
	(zone
		(layer "F.Cu")
		(hatch none 0.5)
		(connect_pads
			(clearance 0)
		)
		(min_thickness 0.25)
		(keepout
			(tracks allowed)
			(vias allowed)
			(pads allowed)
			(copperpour allowed)
			(footprints allowed)
		)
		(placement
			(enabled no)
			(sheetname "")
		)
		(fill
			(thermal_gap 0.5)
			(thermal_bridge_width 0.5)
			(island_removal_mode 0)
		)
		(polygon
			(pts
				(xy 29.647642 -196.266562) (xy 29.647642 -195.822824) (xy 31.972758 -195.822824) (xy 31.972758 -196.266562)
			)
		)
	)
	(zone
		(layer "F.Cu")
		(hatch none 0.5)
		(connect_pads
			(clearance 0)
		)
		(min_thickness 0.25)
		(keepout
			(tracks allowed)
			(vias allowed)
			(pads allowed)
			(copperpour allowed)
			(footprints allowed)
		)
		(placement
			(enabled no)
			(sheetname "")
		)
		(fill
			(thermal_gap 0.5)
			(thermal_bridge_width 0.5)
			(island_removal_mode 0)
		)
		(polygon
			(pts
				(xy 274.143978 -316.116462) (xy 274.143978 -315.672724) (xy 276.469094 -315.672724) (xy 276.469094 -316.116462)
			)
		)
	)
	(zone
		(layer "F.Cu")
		(hatch none 0.5)
		(connect_pads
			(clearance 0)
		)
		(min_thickness 0.25)
		(keepout
			(tracks allowed)
			(vias allowed)
			(pads allowed)
			(copperpour allowed)
			(footprints allowed)
		)
		(placement
			(enabled no)
			(sheetname "")
		)
		(fill
			(thermal_gap 0.5)
			(thermal_bridge_width 0.5)
			(island_removal_mode 0)
		)
		(polygon
			(pts
				(xy 332.235556 -239.061752) (xy 332.438502 -239.264698) (xy 332.481428 -239.264698) (xy 332.925166 -238.821214)
				(xy 332.925166 -238.69904) (xy 332.792324 -238.565944) (xy 332.688184 -238.565944) (xy 332.235556 -239.018572)
			)
		)
	)
	(zone
		(layer "F.Cu")
		(hatch none 0.5)
		(connect_pads
			(clearance 0)
		)
		(min_thickness 0.25)
		(keepout
			(tracks allowed)
			(vias allowed)
			(pads allowed)
			(copperpour allowed)
			(footprints allowed)
		)
		(placement
			(enabled no)
			(sheetname "")
		)
		(fill
			(thermal_gap 0.5)
			(thermal_bridge_width 0.5)
			(island_removal_mode 0)
		)
		(polygon
			(pts
				(xy 41.29151 -213.266782) (xy 41.29151 -212.823044) (xy 43.616626 -212.823044) (xy 43.616626 -213.266782)
			)
		)
	)
	(zone
		(layer "F.Cu")
		(hatch none 0.5)
		(connect_pads
			(clearance 0)
		)
		(min_thickness 0.25)
		(keepout
			(tracks allowed)
			(vias allowed)
			(pads allowed)
			(copperpour allowed)
			(footprints allowed)
		)
		(placement
			(enabled no)
			(sheetname "")
		)
		(fill
			(thermal_gap 0.5)
			(thermal_bridge_width 0.5)
			(island_removal_mode 0)
		)
		(polygon
			(pts
				(xy 29.647642 -287.216596) (xy 29.647642 -286.772858) (xy 31.972758 -286.772858) (xy 31.972758 -287.216596)
			)
		)
	)
	(zone
		(layer "F.Cu")
		(hatch none 0.5)
		(connect_pads
			(clearance 0)
		)
		(min_thickness 0.25)
		(keepout
			(tracks not_allowed)
			(vias allowed)
			(pads allowed)
			(copperpour not_allowed)
			(footprints allowed)
		)
		(placement
			(enabled no)
			(sheetname "")
		)
		(fill
			(thermal_gap 0.5)
			(thermal_bridge_width 0.5)
			(island_removal_mode 0)
		)
		(polygon
			(pts
				(arc
					(start 72.632824 -47.049944)
					(mid 70.382892 -49.299876)
					(end 68.13296 -47.049944)
				)
				(arc
					(start 68.13296 -47.049944)
					(mid 70.382892 -44.800012)
					(end 72.632824 -47.049944)
				)
			)
		)
		(polygon
			(pts
				(arc
					(start 68.482972 -47.049944)
					(mid 70.382892 -45.150024)
					(end 72.282812 -47.049944)
				)
				(arc
					(start 72.282812 -47.049944)
					(mid 70.382892 -48.949864)
					(end 68.482972 -47.049944)
				)
			)
		)
	)
	(zone
		(layer "F.Cu")
		(hatch none 0.5)
		(connect_pads
			(clearance 0)
		)
		(min_thickness 0.25)
		(keepout
			(tracks allowed)
			(vias allowed)
			(pads allowed)
			(copperpour allowed)
			(footprints allowed)
		)
		(placement
			(enabled no)
			(sheetname "")
		)
		(fill
			(thermal_gap 0.5)
			(thermal_bridge_width 0.5)
			(island_removal_mode 0)
		)
		(polygon
			(pts
				(xy 157.791658 -220.804994) (xy 157.791658 -220.576394) (xy 159.823658 -220.576394) (xy 159.823658 -220.804994)
			)
		)
	)
	(zone
		(layer "F.Cu")
		(hatch none 0.5)
		(connect_pads
			(clearance 0)
		)
		(min_thickness 0.25)
		(keepout
			(tracks allowed)
			(vias allowed)
			(pads allowed)
			(copperpour allowed)
			(footprints allowed)
		)
		(placement
			(enabled no)
			(sheetname "")
		)
		(fill
			(thermal_gap 0.5)
			(thermal_bridge_width 0.5)
			(island_removal_mode 0)
		)
		(polygon
			(pts
				(xy 56.37911 -280.416508) (xy 56.37911 -279.97277) (xy 58.704226 -279.97277) (xy 58.704226 -280.416508)
			)
		)
	)
	(zone
		(layer "F.Cu")
		(hatch none 0.5)
		(connect_pads
			(clearance 0)
		)
		(min_thickness 0.25)
		(keepout
			(tracks allowed)
			(vias allowed)
			(pads allowed)
			(copperpour allowed)
			(footprints allowed)
		)
		(placement
			(enabled no)
			(sheetname "")
		)
		(fill
			(thermal_gap 0.5)
			(thermal_bridge_width 0.5)
			(island_removal_mode 0)
		)
		(polygon
			(pts
				(xy 165.335458 -306.654962) (xy 165.335458 -306.426362) (xy 167.367458 -306.426362) (xy 167.367458 -306.654962)
			)
		)
	)
	(zone
		(layer "F.Cu")
		(hatch none 0.5)
		(connect_pads
			(clearance 0)
		)
		(min_thickness 0.25)
		(keepout
			(tracks allowed)
			(vias allowed)
			(pads allowed)
			(copperpour allowed)
			(footprints allowed)
		)
		(placement
			(enabled no)
			(sheetname "")
		)
		(fill
			(thermal_gap 0.5)
			(thermal_bridge_width 0.5)
			(island_removal_mode 0)
		)
		(polygon
			(pts
				(xy 442.05017 -276.056852) (xy 440.01817 -276.056852) (xy 440.01817 -276.054566) (xy 439.839354 -276.054566)
				(xy 439.839354 -275.81733) (xy 439.702702 -275.680678) (xy 439.697114 -275.680678) (xy 439.658252 -275.641816)
				(xy 439.658252 -275.641308) (xy 439.658252 -275.418296) (xy 439.811922 -275.264626) (xy 442.27115 -275.264626)
				(xy 442.412374 -275.40585) (xy 442.412374 -275.602954) (xy 442.33084 -275.684488) (xy 442.24702 -275.768308)
				(xy 442.24702 -276.056852) (xy 442.233304 -276.056852) (xy 442.186314 -276.056852)
			)
		)
	)
	(zone
		(layer "F.Cu")
		(hatch none 0.5)
		(connect_pads
			(clearance 0)
		)
		(min_thickness 0.25)
		(keepout
			(tracks allowed)
			(vias allowed)
			(pads allowed)
			(copperpour allowed)
			(footprints allowed)
		)
		(placement
			(enabled no)
			(sheetname "")
		)
		(fill
			(thermal_gap 0.5)
			(thermal_bridge_width 0.5)
			(island_removal_mode 0)
		)
		(polygon
			(pts
				(xy 25.83434 -166.642288) (xy 25.83434 -163.005008) (xy 29.49448 -163.005008) (xy 29.49448 -166.642288)
			)
		)
	)
	(zone
		(layer "F.Cu")
		(hatch none 0.5)
		(connect_pads
			(clearance 0)
		)
		(min_thickness 0.25)
		(keepout
			(tracks allowed)
			(vias allowed)
			(pads allowed)
			(copperpour allowed)
			(footprints allowed)
		)
		(placement
			(enabled no)
			(sheetname "")
		)
		(fill
			(thermal_gap 0.5)
			(thermal_bridge_width 0.5)
			(island_removal_mode 0)
		)
		(polygon
			(pts
				(xy 289.231578 -250.666504) (xy 289.231578 -250.222766) (xy 291.556694 -250.222766) (xy 291.556694 -250.666504)
			)
		)
	)
	(zone
		(layer "F.Cu")
		(hatch none 0.5)
		(connect_pads
			(clearance 0)
		)
		(min_thickness 0.25)
		(keepout
			(tracks allowed)
			(vias allowed)
			(pads allowed)
			(copperpour allowed)
			(footprints allowed)
		)
		(placement
			(enabled no)
			(sheetname "")
		)
		(fill
			(thermal_gap 0.5)
			(thermal_bridge_width 0.5)
			(island_removal_mode 0)
		)
		(polygon
			(pts
				(xy 195.510658 -310.90489) (xy 195.510658 -310.67629) (xy 197.542658 -310.67629) (xy 197.542658 -310.90489)
			)
		)
	)
	(zone
		(layer "F.Cu")
		(hatch none 0.5)
		(connect_pads
			(clearance 0)
		)
		(min_thickness 0.25)
		(keepout
			(tracks allowed)
			(vias allowed)
			(pads allowed)
			(copperpour allowed)
			(footprints allowed)
		)
		(placement
			(enabled no)
			(sheetname "")
		)
		(fill
			(thermal_gap 0.5)
			(thermal_bridge_width 0.5)
			(island_removal_mode 0)
		)
		(polygon
			(pts
				(xy 289.231578 -210.716622) (xy 289.231578 -210.272884) (xy 291.556694 -210.272884) (xy 291.556694 -210.716622)
			)
		)
	)
	(zone
		(layer "F.Cu")
		(hatch none 0.5)
		(connect_pads
			(clearance 0)
		)
		(min_thickness 0.25)
		(keepout
			(tracks allowed)
			(vias allowed)
			(pads allowed)
			(copperpour allowed)
			(footprints allowed)
		)
		(placement
			(enabled no)
			(sheetname "")
		)
		(fill
			(thermal_gap 0.5)
			(thermal_bridge_width 0.5)
			(island_removal_mode 0)
		)
		(polygon
			(pts
				(xy 317.122302 -410.948886) (xy 317.122302 -406.105868) (xy 319.006728 -406.105868) (xy 319.006728 -410.948886)
			)
		)
	)
	(zone
		(layer "F.Cu")
		(hatch none 0.5)
		(connect_pads
			(clearance 0)
		)
		(min_thickness 0.25)
		(keepout
			(tracks allowed)
			(vias allowed)
			(pads allowed)
			(copperpour allowed)
			(footprints allowed)
		)
		(placement
			(enabled no)
			(sheetname "")
		)
		(fill
			(thermal_gap 0.5)
			(thermal_bridge_width 0.5)
			(island_removal_mode 0)
		)
		(polygon
			(pts
				(xy 41.29151 -276.16658) (xy 41.29151 -275.722842) (xy 43.616626 -275.722842) (xy 43.616626 -276.16658)
			)
		)
	)
	(zone
		(layer "F.Cu")
		(hatch none 0.5)
		(connect_pads
			(clearance 0)
		)
		(min_thickness 0.25)
		(keepout
			(tracks allowed)
			(vias allowed)
			(pads allowed)
			(copperpour allowed)
			(footprints allowed)
		)
		(placement
			(enabled no)
			(sheetname "")
		)
		(fill
			(thermal_gap 0.5)
			(thermal_bridge_width 0.5)
			(island_removal_mode 0)
		)
		(polygon
			(pts
				(xy 289.231578 -262.566658) (xy 289.231578 -262.12292) (xy 291.556694 -262.12292) (xy 291.556694 -262.566658)
			)
		)
	)
	(zone
		(layer "F.Cu")
		(hatch none 0.5)
		(connect_pads
			(clearance 0)
		)
		(min_thickness 0.25)
		(keepout
			(tracks allowed)
			(vias allowed)
			(pads allowed)
			(copperpour allowed)
			(footprints allowed)
		)
		(placement
			(enabled no)
			(sheetname "")
		)
		(fill
			(thermal_gap 0.5)
			(thermal_bridge_width 0.5)
			(island_removal_mode 0)
		)
		(polygon
			(pts
				(xy 192.066926 -281.776424) (xy 194.098926 -281.776424) (xy 194.098926 -282.005024) (xy 192.066926 -282.005024)
				(xy 191.930782 -282.005024) (xy 191.883792 -282.005024) (xy 191.775842 -282.005024) (xy 191.775842 -281.776424)
				(xy 191.883792 -281.776424) (xy 191.930782 -281.776424)
			)
		)
	)
	(zone
		(layer "F.Cu")
		(hatch none 0.5)
		(connect_pads
			(clearance 0)
		)
		(min_thickness 0.25)
		(keepout
			(tracks allowed)
			(vias allowed)
			(pads allowed)
			(copperpour allowed)
			(footprints allowed)
		)
		(placement
			(enabled no)
			(sheetname "")
		)
		(fill
			(thermal_gap 0.5)
			(thermal_bridge_width 0.5)
			(island_removal_mode 0)
		)
		(polygon
			(pts
				(xy 26.20391 -200.51649) (xy 26.20391 -200.072752) (xy 28.529026 -200.072752) (xy 28.529026 -200.51649)
			)
		)
	)
	(zone
		(layer "F.Cu")
		(hatch none 0.5)
		(connect_pads
			(clearance 0)
		)
		(min_thickness 0.25)
		(keepout
			(tracks not_allowed)
			(vias allowed)
			(pads allowed)
			(copperpour not_allowed)
			(footprints allowed)
		)
		(placement
			(enabled no)
			(sheetname "")
		)
		(fill
			(thermal_gap 0.5)
			(thermal_bridge_width 0.5)
			(island_removal_mode 0)
		)
		(polygon
			(pts
				(xy 41.26992 -393.93114) (xy 41.26992 -390.96442) (xy 41.49598 -390.96442) (xy 41.49598 -393.93114)
			)
		)
	)
	(zone
		(layer "F.Cu")
		(hatch none 0.5)
		(connect_pads
			(clearance 0)
		)
		(min_thickness 0.25)
		(keepout
			(tracks allowed)
			(vias allowed)
			(pads allowed)
			(copperpour allowed)
			(footprints allowed)
		)
		(placement
			(enabled no)
			(sheetname "")
		)
		(fill
			(thermal_gap 0.5)
			(thermal_bridge_width 0.5)
			(island_removal_mode 0)
		)
		(polygon
			(pts
				(xy 277.58771 -299.966634) (xy 277.58771 -299.522896) (xy 279.912826 -299.522896) (xy 279.912826 -299.966634)
			)
		)
	)
	(zone
		(layer "F.Cu")
		(hatch none 0.5)
		(connect_pads
			(clearance 0)
		)
		(min_thickness 0.25)
		(keepout
			(tracks allowed)
			(vias allowed)
			(pads allowed)
			(copperpour allowed)
			(footprints not_allowed)
		)
		(placement
			(enabled no)
			(sheetname "")
		)
		(fill
			(thermal_gap 0.5)
			(thermal_bridge_width 0.5)
			(island_removal_mode 0)
		)
		(polygon
			(pts
				(arc
					(start 86.900004 -22.29993)
					(mid 94.899988 -14.299946)
					(end 102.899972 -22.29993)
				)
				(arc
					(start 102.899972 -22.29993)
					(mid 94.899988 -30.299914)
					(end 86.900004 -22.29993)
				)
			)
		)
	)
	(zone
		(layer "F.Cu")
		(hatch none 0.5)
		(connect_pads
			(clearance 0)
		)
		(min_thickness 0.25)
		(keepout
			(tracks not_allowed)
			(vias allowed)
			(pads allowed)
			(copperpour not_allowed)
			(footprints allowed)
		)
		(placement
			(enabled no)
			(sheetname "")
		)
		(fill
			(thermal_gap 0.5)
			(thermal_bridge_width 0.5)
			(island_removal_mode 0)
		)
		(polygon
			(pts
				(arc
					(start 361.359958 -431.360072)
					(mid 359.774998 -432.945032)
					(end 358.190038 -431.360072)
				)
				(arc
					(start 358.190038 -431.360072)
					(mid 359.774998 -429.775112)
					(end 361.359958 -431.360072)
				)
			)
		)
	)
	(zone
		(layer "F.Cu")
		(hatch none 0.5)
		(connect_pads
			(clearance 0)
		)
		(min_thickness 0.25)
		(keepout
			(tracks allowed)
			(vias allowed)
			(pads allowed)
			(copperpour allowed)
			(footprints not_allowed)
		)
		(placement
			(enabled no)
			(sheetname "")
		)
		(fill
			(thermal_gap 0.5)
			(thermal_bridge_width 0.5)
			(island_removal_mode 0)
		)
		(polygon
			(pts
				(arc
					(start 274.004532 -21.850096)
					(mid 281.437588 -15.350073)
					(end 288.870644 -21.850096)
				)
			)
		)
	)
	(zone
		(layer "F.Cu")
		(hatch none 0.5)
		(connect_pads
			(clearance 0)
		)
		(min_thickness 0.25)
		(keepout
			(tracks allowed)
			(vias allowed)
			(pads allowed)
			(copperpour allowed)
			(footprints allowed)
		)
		(placement
			(enabled no)
			(sheetname "")
		)
		(fill
			(thermal_gap 0.5)
			(thermal_bridge_width 0.5)
			(island_removal_mode 0)
		)
		(polygon
			(pts
				(xy 460.88808 -268.472412) (xy 460.88808 -268.956536) (xy 460.88808 -269.254986) (xy 460.570326 -269.254986)
				(xy 458.538326 -269.254986) (xy 458.220318 -269.254986) (xy 458.122782 -269.254986) (xy 458.122782 -268.356842)
				(xy 460.88808 -268.356842)
			)
		)
	)
	(zone
		(layer "F.Cu")
		(hatch none 0.5)
		(connect_pads
			(clearance 0)
		)
		(min_thickness 0.25)
		(keepout
			(tracks allowed)
			(vias allowed)
			(pads allowed)
			(copperpour allowed)
			(footprints allowed)
		)
		(placement
			(enabled no)
			(sheetname "")
		)
		(fill
			(thermal_gap 0.5)
			(thermal_bridge_width 0.5)
			(island_removal_mode 0)
		)
		(polygon
			(pts
				(xy 52.813966 -156.8577) (xy 54.145942 -156.8577) (xy 54.344824 -157.056582) (xy 54.344824 -158.848552)
				(xy 53.541676 -159.6517) (xy 51.063652 -159.6517) (xy 49.70399 -158.292038) (xy 49.70399 -152.800304)
				(xy 50.843688 -151.660606) (xy 54.764178 -151.660606) (xy 55.395622 -152.29205) (xy 55.395622 -154.008074)
				(xy 54.839108 -154.564588) (xy 52.690522 -154.564588) (xy 52.621942 -154.633168) (xy 52.621942 -156.665676)
			)
		)
	)
	(zone
		(layer "F.Cu")
		(hatch none 0.5)
		(connect_pads
			(clearance 0)
		)
		(min_thickness 0.25)
		(keepout
			(tracks allowed)
			(vias allowed)
			(pads allowed)
			(copperpour allowed)
			(footprints not_allowed)
		)
		(placement
			(enabled no)
			(sheetname "")
		)
		(fill
			(thermal_gap 0.5)
			(thermal_bridge_width 0.5)
			(island_removal_mode 0)
		)
		(polygon
			(pts
				(arc
					(start 10.199878 -435.600094)
					(mid 12.999974 -432.799998)
					(end 15.80007 -435.600094)
				)
				(arc
					(start 15.80007 -435.600094)
					(mid 12.999974 -438.40019)
					(end 10.199878 -435.600094)
				)
			)
		)
	)
	(zone
		(layer "F.Cu")
		(hatch none 0.5)
		(connect_pads
			(clearance 0)
		)
		(min_thickness 0.25)
		(keepout
			(tracks allowed)
			(vias allowed)
			(pads allowed)
			(copperpour allowed)
			(footprints allowed)
		)
		(placement
			(enabled no)
			(sheetname "")
		)
		(fill
			(thermal_gap 0.5)
			(thermal_bridge_width 0.5)
			(island_removal_mode 0)
		)
		(polygon
			(pts
				(xy 192.066926 -304.72634) (xy 194.098926 -304.72634) (xy 194.098926 -304.95494) (xy 192.066926 -304.95494)
				(xy 191.930782 -304.95494) (xy 191.883792 -304.95494) (xy 191.883792 -304.72634) (xy 191.930782 -304.72634)
			)
		)
	)
	(zone
		(layer "F.Cu")
		(hatch none 0.5)
		(connect_pads
			(clearance 0)
		)
		(min_thickness 0.25)
		(keepout
			(tracks allowed)
			(vias allowed)
			(pads allowed)
			(copperpour allowed)
			(footprints allowed)
		)
		(placement
			(enabled no)
			(sheetname "")
		)
		(fill
			(thermal_gap 0.5)
			(thermal_bridge_width 0.5)
			(island_removal_mode 0)
		)
		(polygon
			(pts
				(xy 102.625398 -331.689456) (xy 102.625398 -335.695036) (xy 103.105458 -336.175096) (xy 105.170478 -336.175096)
				(xy 105.442258 -335.903316) (xy 105.442258 -334.049116) (xy 105.693718 -333.797656) (xy 107.613958 -333.797656)
				(xy 108.030518 -333.381096) (xy 108.030518 -331.890116) (xy 107.382818 -331.242416) (xy 103.072438 -331.242416)
			)
		)
	)
	(zone
		(layer "F.Cu")
		(hatch none 0.5)
		(connect_pads
			(clearance 0)
		)
		(min_thickness 0.25)
		(keepout
			(tracks allowed)
			(vias allowed)
			(pads allowed)
			(copperpour allowed)
			(footprints allowed)
		)
		(placement
			(enabled no)
			(sheetname "")
		)
		(fill
			(thermal_gap 0.5)
			(thermal_bridge_width 0.5)
			(island_removal_mode 0)
		)
		(polygon
			(pts
				(xy 289.231578 -291.466524) (xy 289.231578 -291.022786) (xy 291.556694 -291.022786) (xy 291.556694 -291.466524)
			)
		)
	)
	(zone
		(layer "F.Cu")
		(hatch none 0.5)
		(connect_pads
			(clearance 0)
		)
		(min_thickness 0.25)
		(keepout
			(tracks allowed)
			(vias allowed)
			(pads allowed)
			(copperpour allowed)
			(footprints allowed)
		)
		(placement
			(enabled no)
			(sheetname "")
		)
		(fill
			(thermal_gap 0.5)
			(thermal_bridge_width 0.5)
			(island_removal_mode 0)
		)
		(polygon
			(pts
				(xy 176.979326 -214.626444) (xy 179.011326 -214.626444) (xy 179.011326 -214.855044) (xy 176.979326 -214.855044)
				(xy 176.843182 -214.855044) (xy 176.796192 -214.855044) (xy 176.796192 -214.626444) (xy 176.843182 -214.626444)
			)
		)
	)
	(zone
		(layer "F.Cu")
		(hatch none 0.5)
		(connect_pads
			(clearance 0)
		)
		(min_thickness 0.25)
		(keepout
			(tracks allowed)
			(vias allowed)
			(pads allowed)
			(copperpour allowed)
			(footprints allowed)
		)
		(placement
			(enabled no)
			(sheetname "")
		)
		(fill
			(thermal_gap 0.5)
			(thermal_bridge_width 0.5)
			(island_removal_mode 0)
		)
		(polygon
			(pts
				(xy 292.67531 -260.866636) (xy 292.67531 -260.422898) (xy 295.000426 -260.422898) (xy 295.000426 -260.866636)
			)
		)
	)
	(zone
		(layer "F.Cu")
		(hatch none 0.5)
		(connect_pads
			(clearance 0)
		)
		(min_thickness 0.25)
		(keepout
			(tracks allowed)
			(vias allowed)
			(pads allowed)
			(copperpour allowed)
			(footprints allowed)
		)
		(placement
			(enabled no)
			(sheetname "")
		)
		(fill
			(thermal_gap 0.5)
			(thermal_bridge_width 0.5)
			(island_removal_mode 0)
		)
		(polygon
			(pts
				(xy 19.2024 -392.49604) (xy 19.2024 -388.68604) (xy 24.36622 -388.68604) (xy 24.36622 -392.49604)
			)
		)
	)
	(zone
		(layer "F.Cu")
		(hatch none 0.5)
		(connect_pads
			(clearance 0)
		)
		(min_thickness 0.25)
		(keepout
			(tracks allowed)
			(vias allowed)
			(pads allowed)
			(copperpour allowed)
			(footprints allowed)
		)
		(placement
			(enabled no)
			(sheetname "")
		)
		(fill
			(thermal_gap 0.5)
			(thermal_bridge_width 0.5)
			(island_removal_mode 0)
		)
		(polygon
			(pts
				(xy 161.891726 -281.154886) (xy 161.891726 -280.926286) (xy 163.923726 -280.926286) (xy 163.923726 -281.154886)
			)
		)
	)
	(zone
		(layer "F.Cu")
		(hatch none 0.5)
		(connect_pads
			(clearance 0)
		)
		(min_thickness 0.25)
		(keepout
			(tracks allowed)
			(vias allowed)
			(pads allowed)
			(copperpour allowed)
			(footprints allowed)
		)
		(placement
			(enabled no)
			(sheetname "")
		)
		(fill
			(thermal_gap 0.5)
			(thermal_bridge_width 0.5)
			(island_removal_mode 0)
		)
		(polygon
			(pts
				(xy 259.056378 -295.716452) (xy 259.056378 -295.272714) (xy 261.381494 -295.272714) (xy 261.381494 -295.716452)
			)
		)
	)
	(zone
		(layer "F.Cu")
		(hatch none 0.5)
		(connect_pads
			(clearance 0)
		)
		(min_thickness 0.25)
		(keepout
			(tracks allowed)
			(vias allowed)
			(pads allowed)
			(copperpour allowed)
			(footprints allowed)
		)
		(placement
			(enabled no)
			(sheetname "")
		)
		(fill
			(thermal_gap 0.5)
			(thermal_bridge_width 0.5)
			(island_removal_mode 0)
		)
		(polygon
			(pts
				(xy 306.57292 -61.064648) (xy 306.57292 -59.469528) (xy 308.40172 -59.469528) (xy 308.40172 -61.064648)
			)
		)
	)
	(zone
		(layer "F.Cu")
		(hatch none 0.5)
		(connect_pads
			(clearance 0)
		)
		(min_thickness 0.25)
		(keepout
			(tracks allowed)
			(vias allowed)
			(pads allowed)
			(copperpour allowed)
			(footprints allowed)
		)
		(placement
			(enabled no)
			(sheetname "")
		)
		(fill
			(thermal_gap 0.5)
			(thermal_bridge_width 0.5)
			(island_removal_mode 0)
		)
		(polygon
			(pts
				(xy 274.143978 -306.766468) (xy 274.143978 -306.32273) (xy 276.469094 -306.32273) (xy 276.469094 -306.766468)
			)
		)
	)
	(zone
		(layer "F.Cu")
		(hatch none 0.5)
		(connect_pads
			(clearance 0)
		)
		(min_thickness 0.25)
		(keepout
			(tracks allowed)
			(vias allowed)
			(pads allowed)
			(copperpour allowed)
			(footprints allowed)
		)
		(placement
			(enabled no)
			(sheetname "")
		)
		(fill
			(thermal_gap 0.5)
			(thermal_bridge_width 0.5)
			(island_removal_mode 0)
		)
		(polygon
			(pts
				(xy 259.056378 -313.566556) (xy 259.056378 -313.122818) (xy 261.381494 -313.122818) (xy 261.381494 -313.566556)
			)
		)
	)
	(zone
		(layer "F.Cu")
		(hatch none 0.5)
		(connect_pads
			(clearance 0)
		)
		(min_thickness 0.25)
		(keepout
			(tracks allowed)
			(vias allowed)
			(pads allowed)
			(copperpour allowed)
			(footprints allowed)
		)
		(placement
			(enabled no)
			(sheetname "")
		)
		(fill
			(thermal_gap 0.5)
			(thermal_bridge_width 0.5)
			(island_removal_mode 0)
		)
		(polygon
			(pts
				(xy 335.58226 -287.348168) (xy 335.86928 -287.348168) (xy 335.89976 -287.317688) (xy 335.89976 -286.690308)
				(xy 335.8134 -286.603948) (xy 335.62544 -286.603948) (xy 335.55178 -286.677608) (xy 335.55178 -287.317688)
			)
		)
	)
	(zone
		(layer "F.Cu")
		(hatch none 0.5)
		(connect_pads
			(clearance 0)
		)
		(min_thickness 0.25)
		(keepout
			(tracks not_allowed)
			(vias allowed)
			(pads allowed)
			(copperpour not_allowed)
			(footprints allowed)
		)
		(placement
			(enabled no)
			(sheetname "")
		)
		(fill
			(thermal_gap 0.5)
			(thermal_bridge_width 0.5)
			(island_removal_mode 0)
		)
		(polygon
			(pts
				(xy 423.804334 -364.631986) (xy 427.73092 -364.631986) (xy 427.73092 -364.607094) (xy 427.5709 -364.447074)
				(xy 426.192188 -364.447074) (xy 426.192188 -362.288074) (xy 428.348902 -362.288074) (xy 428.348902 -362.038392)
				(xy 426.02658 -362.038392) (xy 426.02658 -362.364528) (xy 425.90085 -362.364528) (xy 425.90085 -364.391448)
				(xy 424.04665 -364.391448) (xy 424.04665 -364.150402) (xy 423.804334 -364.150402)
			)
		)
	)
	(zone
		(layer "F.Cu")
		(hatch none 0.5)
		(connect_pads
			(clearance 0)
		)
		(min_thickness 0.25)
		(keepout
			(tracks allowed)
			(vias allowed)
			(pads allowed)
			(copperpour allowed)
			(footprints allowed)
		)
		(placement
			(enabled no)
			(sheetname "")
		)
		(fill
			(thermal_gap 0.5)
			(thermal_bridge_width 0.5)
			(island_removal_mode 0)
		)
		(polygon
			(pts
				(xy 26.20391 -213.266528) (xy 26.20391 -212.82279) (xy 28.529026 -212.82279) (xy 28.529026 -213.266528)
			)
		)
	)
	(zone
		(layer "F.Cu")
		(hatch none 0.5)
		(connect_pads
			(clearance 0)
		)
		(min_thickness 0.25)
		(keepout
			(tracks allowed)
			(vias allowed)
			(pads allowed)
			(copperpour allowed)
			(footprints allowed)
		)
		(placement
			(enabled no)
			(sheetname "")
		)
		(fill
			(thermal_gap 0.5)
			(thermal_bridge_width 0.5)
			(island_removal_mode 0)
		)
		(polygon
			(pts
				(xy 440.006994 -240.976404) (xy 442.038994 -240.976404) (xy 442.038994 -240.97869) (xy 442.21781 -240.97869)
				(xy 442.21781 -241.215926) (xy 442.355732 -241.215926) (xy 442.398912 -241.259106) (xy 442.398912 -241.391948)
				(xy 442.398912 -241.695986) (xy 442.326268 -241.76863) (xy 439.786014 -241.76863) (xy 439.64479 -241.627406)
				(xy 439.64479 -241.430302) (xy 439.726324 -241.348768) (xy 439.726324 -240.976404) (xy 439.82386 -240.976404)
				(xy 439.87085 -240.976404)
			)
		)
	)
	(zone
		(layer "F.Cu")
		(hatch none 0.5)
		(connect_pads
			(clearance 0)
		)
		(min_thickness 0.25)
		(keepout
			(tracks allowed)
			(vias allowed)
			(pads allowed)
			(copperpour allowed)
			(footprints allowed)
		)
		(placement
			(enabled no)
			(sheetname "")
		)
		(fill
			(thermal_gap 0.5)
			(thermal_bridge_width 0.5)
			(island_removal_mode 0)
		)
		(polygon
			(pts
				(xy 158.91256 -43.01236) (xy 158.91256 -42.47896) (xy 160.70834 -42.47896) (xy 160.70834 -43.01236)
			)
		)
	)
	(zone
		(layer "F.Cu")
		(hatch none 0.5)
		(connect_pads
			(clearance 0)
		)
		(min_thickness 0.25)
		(keepout
			(tracks allowed)
			(vias allowed)
			(pads allowed)
			(copperpour allowed)
			(footprints allowed)
		)
		(placement
			(enabled no)
			(sheetname "")
		)
		(fill
			(thermal_gap 0.5)
			(thermal_bridge_width 0.5)
			(island_removal_mode 0)
		)
		(polygon
			(pts
				(xy 26.20391 -308.46649) (xy 26.20391 -308.022752) (xy 28.529026 -308.022752) (xy 28.529026 -308.46649)
			)
		)
	)
	(zone
		(layer "F.Cu")
		(hatch none 0.5)
		(connect_pads
			(clearance 0)
		)
		(min_thickness 0.25)
		(keepout
			(tracks allowed)
			(vias allowed)
			(pads allowed)
			(copperpour allowed)
			(footprints allowed)
		)
		(placement
			(enabled no)
			(sheetname "")
		)
		(fill
			(thermal_gap 0.5)
			(thermal_bridge_width 0.5)
			(island_removal_mode 0)
		)
		(polygon
			(pts
				(xy 14.560042 -305.916584) (xy 14.560042 -305.472846) (xy 16.885158 -305.472846) (xy 16.885158 -305.916584)
			)
		)
	)
	(zone
		(layer "F.Cu")
		(hatch none 0.5)
		(connect_pads
			(clearance 0)
		)
		(min_thickness 0.25)
		(keepout
			(tracks allowed)
			(vias allowed)
			(pads allowed)
			(copperpour allowed)
			(footprints allowed)
		)
		(placement
			(enabled no)
			(sheetname "")
		)
		(fill
			(thermal_gap 0.5)
			(thermal_bridge_width 0.5)
			(island_removal_mode 0)
		)
		(polygon
			(pts
				(xy 440.006994 -291.126418) (xy 442.038994 -291.126418) (xy 442.038994 -291.355018) (xy 440.006994 -291.355018)
				(xy 439.87085 -291.355018) (xy 439.82386 -291.355018) (xy 439.82386 -291.126418) (xy 439.87085 -291.126418)
			)
		)
	)
	(zone
		(layer "F.Cu")
		(hatch none 0.5)
		(connect_pads
			(clearance 0)
		)
		(min_thickness 0.25)
		(keepout
			(tracks allowed)
			(vias allowed)
			(pads allowed)
			(copperpour allowed)
			(footprints allowed)
		)
		(placement
			(enabled no)
			(sheetname "")
		)
		(fill
			(thermal_gap 0.5)
			(thermal_bridge_width 0.5)
			(island_removal_mode 0)
		)
		(polygon
			(pts
				(xy 341.48522 -333.45755) (xy 342.8238 -333.45755) (xy 343.2175 -333.85125) (xy 343.2175 -336.06613)
				(xy 343.408 -336.25663) (xy 346.95384 -336.25663) (xy 347.16974 -336.47253) (xy 347.16974 -338.63407)
				(xy 347.16974 -338.891118) (xy 347.105986 -338.954872) (xy 341.517986 -338.954872) (xy 341.12962 -338.566506)
				(xy 341.12962 -338.34959) (xy 341.12962 -333.81315)
			)
		)
	)
	(zone
		(layer "F.Cu")
		(hatch none 0.5)
		(connect_pads
			(clearance 0)
		)
		(min_thickness 0.25)
		(keepout
			(tracks allowed)
			(vias allowed)
			(pads allowed)
			(copperpour allowed)
			(footprints allowed)
		)
		(placement
			(enabled no)
			(sheetname "")
		)
		(fill
			(thermal_gap 0.5)
			(thermal_bridge_width 0.5)
			(island_removal_mode 0)
		)
		(polygon
			(pts
				(xy 195.510658 -217.40495) (xy 195.510658 -217.17635) (xy 197.542658 -217.17635) (xy 197.542658 -217.40495)
			)
		)
	)
	(zone
		(layer "F.Cu")
		(hatch none 0.5)
		(connect_pads
			(clearance 0)
		)
		(min_thickness 0.25)
		(keepout
			(tracks allowed)
			(vias allowed)
			(pads allowed)
			(copperpour allowed)
			(footprints allowed)
		)
		(placement
			(enabled no)
			(sheetname "")
		)
		(fill
			(thermal_gap 0.5)
			(thermal_bridge_width 0.5)
			(island_removal_mode 0)
		)
		(polygon
			(pts
				(xy 306.644294 -238.766604) (xy 304.319178 -238.766604) (xy 303.972214 -238.766604) (xy 303.972214 -237.572042)
				(xy 306.907946 -237.572042) (xy 306.907946 -238.766604)
			)
		)
	)
	(zone
		(layer "F.Cu")
		(hatch none 0.5)
		(connect_pads
			(clearance 0)
		)
		(min_thickness 0.25)
		(keepout
			(tracks allowed)
			(vias allowed)
			(pads allowed)
			(copperpour allowed)
			(footprints allowed)
		)
		(placement
			(enabled no)
			(sheetname "")
		)
		(fill
			(thermal_gap 0.5)
			(thermal_bridge_width 0.5)
			(island_removal_mode 0)
		)
		(polygon
			(pts
				(xy 81.218532 -404.802594) (xy 81.218532 -399.959576) (xy 83.102958 -399.959576) (xy 83.102958 -404.802594)
			)
		)
	)
	(zone
		(layer "F.Cu")
		(hatch none 0.5)
		(connect_pads
			(clearance 0)
		)
		(min_thickness 0.25)
		(keepout
			(tracks allowed)
			(vias allowed)
			(pads allowed)
			(copperpour allowed)
			(footprints allowed)
		)
		(placement
			(enabled no)
			(sheetname "")
		)
		(fill
			(thermal_gap 0.5)
			(thermal_bridge_width 0.5)
			(island_removal_mode 0)
		)
		(polygon
			(pts
				(xy 44.735242 -227.716588) (xy 44.735242 -227.27285) (xy 47.060358 -227.27285) (xy 47.060358 -227.716588)
			)
		)
	)
	(zone
		(layer "F.Cu")
		(hatch none 0.5)
		(connect_pads
			(clearance 0)
		)
		(min_thickness 0.25)
		(keepout
			(tracks allowed)
			(vias allowed)
			(pads allowed)
			(copperpour allowed)
			(footprints allowed)
		)
		(placement
			(enabled no)
			(sheetname "")
		)
		(fill
			(thermal_gap 0.5)
			(thermal_bridge_width 0.5)
			(island_removal_mode 0)
		)
		(polygon
			(pts
				(xy 195.510658 -230.154988) (xy 195.510658 -229.926388) (xy 197.542658 -229.926388) (xy 197.542658 -230.154988)
			)
		)
	)
	(zone
		(layer "F.Cu")
		(hatch none 0.5)
		(connect_pads
			(clearance 0)
		)
		(min_thickness 0.25)
		(keepout
			(tracks allowed)
			(vias allowed)
			(pads allowed)
			(copperpour allowed)
			(footprints allowed)
		)
		(placement
			(enabled no)
			(sheetname "")
		)
		(fill
			(thermal_gap 0.5)
			(thermal_bridge_width 0.5)
			(island_removal_mode 0)
		)
		(polygon
			(pts
				(xy 44.735242 -302.51654) (xy 44.735242 -302.072802) (xy 47.060358 -302.072802) (xy 47.060358 -302.51654)
			)
		)
	)
	(zone
		(layer "F.Cu")
		(hatch none 0.5)
		(connect_pads
			(clearance 0)
		)
		(min_thickness 0.25)
		(keepout
			(tracks allowed)
			(vias allowed)
			(pads allowed)
			(copperpour allowed)
			(footprints allowed)
		)
		(placement
			(enabled no)
			(sheetname "")
		)
		(fill
			(thermal_gap 0.5)
			(thermal_bridge_width 0.5)
			(island_removal_mode 0)
		)
		(polygon
			(pts
				(xy 323.248782 -410.948886) (xy 323.248782 -406.105868) (xy 325.133208 -406.105868) (xy 325.133208 -410.948886)
			)
		)
	)
	(zone
		(layer "F.Cu")
		(hatch none 0.5)
		(connect_pads
			(clearance 0)
		)
		(min_thickness 0.25)
		(keepout
			(tracks allowed)
			(vias allowed)
			(pads allowed)
			(copperpour allowed)
			(footprints allowed)
		)
		(placement
			(enabled no)
			(sheetname "")
		)
		(fill
			(thermal_gap 0.5)
			(thermal_bridge_width 0.5)
			(island_removal_mode 0)
		)
		(polygon
			(pts
				(xy 413.275526 -220.804994) (xy 413.275526 -220.576394) (xy 415.307526 -220.576394) (xy 415.307526 -220.804994)
			)
		)
	)
	(zone
		(layer "F.Cu")
		(hatch none 0.5)
		(connect_pads
			(clearance 0)
		)
		(min_thickness 0.25)
		(keepout
			(tracks allowed)
			(vias allowed)
			(pads allowed)
			(copperpour allowed)
			(footprints allowed)
		)
		(placement
			(enabled no)
			(sheetname "")
		)
		(fill
			(thermal_gap 0.5)
			(thermal_bridge_width 0.5)
			(island_removal_mode 0)
		)
		(polygon
			(pts
				(xy 180.423058 -292.204902) (xy 180.423058 -291.976302) (xy 182.455058 -291.976302) (xy 182.455058 -292.204902)
			)
		)
	)
	(zone
		(layer "F.Cu")
		(hatch none 0.5)
		(connect_pads
			(clearance 0)
		)
		(min_thickness 0.25)
		(keepout
			(tracks allowed)
			(vias allowed)
			(pads allowed)
			(copperpour allowed)
			(footprints allowed)
		)
		(placement
			(enabled no)
			(sheetname "")
		)
		(fill
			(thermal_gap 0.5)
			(thermal_bridge_width 0.5)
			(island_removal_mode 0)
		)
		(polygon
			(pts
				(xy 11.11631 -207.316578) (xy 11.11631 -206.87284) (xy 13.441426 -206.87284) (xy 13.441426 -207.316578)
			)
		)
	)
	(zone
		(layer "F.Cu")
		(hatch none 0.5)
		(connect_pads
			(clearance 0)
		)
		(min_thickness 0.25)
		(keepout
			(tracks allowed)
			(vias allowed)
			(pads allowed)
			(copperpour allowed)
			(footprints allowed)
		)
		(placement
			(enabled no)
			(sheetname "")
		)
		(fill
			(thermal_gap 0.5)
			(thermal_bridge_width 0.5)
			(island_removal_mode 0)
		)
		(polygon
			(pts
				(xy 311.91708 -248.116598) (xy 311.91708 -247.67286) (xy 314.12688 -247.67286) (xy 314.12688 -248.116598)
			)
		)
	)
	(zone
		(layer "F.Cu")
		(hatch none 0.5)
		(connect_pads
			(clearance 0)
		)
		(min_thickness 0.25)
		(keepout
			(tracks allowed)
			(vias allowed)
			(pads allowed)
			(copperpour allowed)
			(footprints allowed)
		)
		(placement
			(enabled no)
			(sheetname "")
		)
		(fill
			(thermal_gap 0.5)
			(thermal_bridge_width 0.5)
			(island_removal_mode 0)
		)
		(polygon
			(pts
				(xy 229.00132 -59.466226) (xy 229.00132 -51.223926) (xy 232.67162 -51.223926) (xy 232.67162 -59.466226)
			)
		)
	)
	(zone
		(layer "F.Cu")
		(hatch none 0.5)
		(connect_pads
			(clearance 0)
		)
		(min_thickness 0.25)
		(keepout
			(tracks allowed)
			(vias allowed)
			(pads allowed)
			(copperpour allowed)
			(footprints allowed)
		)
		(placement
			(enabled no)
			(sheetname "")
		)
		(fill
			(thermal_gap 0.5)
			(thermal_bridge_width 0.5)
			(island_removal_mode 0)
		)
		(polygon
			(pts
				(xy 310.088026 -233.666538) (xy 307.76291 -233.666538) (xy 307.63845 -233.666538) (xy 307.63845 -232.711752)
				(xy 310.146954 -232.711752) (xy 310.146954 -233.666538)
			)
		)
	)
	(zone
		(layer "F.Cu")
		(hatch none 0.5)
		(connect_pads
			(clearance 0)
		)
		(min_thickness 0.25)
		(keepout
			(tracks allowed)
			(vias allowed)
			(pads allowed)
			(copperpour allowed)
			(footprints allowed)
		)
		(placement
			(enabled no)
			(sheetname "")
		)
		(fill
			(thermal_gap 0.5)
			(thermal_bridge_width 0.5)
			(island_removal_mode 0)
		)
		(polygon
			(pts
				(xy 210.598258 -270.955008) (xy 210.598258 -270.726408) (xy 212.630258 -270.726408) (xy 212.630258 -270.955008)
			)
		)
	)
	(zone
		(layer "F.Cu")
		(hatch none 0.5)
		(connect_pads
			(clearance 0)
		)
		(min_thickness 0.25)
		(keepout
			(tracks allowed)
			(vias allowed)
			(pads allowed)
			(copperpour allowed)
			(footprints allowed)
		)
		(placement
			(enabled no)
			(sheetname "")
		)
		(fill
			(thermal_gap 0.5)
			(thermal_bridge_width 0.5)
			(island_removal_mode 0)
		)
		(polygon
			(pts
				(xy 235.9406 -59.268106) (xy 235.9406 -51.422046) (xy 235.9406 -49.760886) (xy 236.15396 -49.547526)
				(xy 238.57204 -49.547526) (xy 238.87938 -49.854866) (xy 238.87938 -51.223926) (xy 239.0775 -51.422046)
				(xy 242.61572 -51.422046) (xy 242.61572 -59.268106)
			)
		)
	)
	(zone
		(layer "F.Cu")
		(hatch none 0.5)
		(connect_pads
			(clearance 0)
		)
		(min_thickness 0.25)
		(keepout
			(tracks allowed)
			(vias allowed)
			(pads allowed)
			(copperpour allowed)
			(footprints allowed)
		)
		(placement
			(enabled no)
			(sheetname "")
		)
		(fill
			(thermal_gap 0.5)
			(thermal_bridge_width 0.5)
			(island_removal_mode 0)
		)
		(polygon
			(pts
				(xy 334.18018 -284.955488) (xy 334.4672 -284.955488) (xy 334.49768 -284.925008) (xy 334.49768 -284.297628)
				(xy 334.41132 -284.211268) (xy 334.22336 -284.211268) (xy 334.1497 -284.284928) (xy 334.1497 -284.925008)
			)
		)
	)
	(zone
		(layer "F.Cu")
		(hatch none 0.5)
		(connect_pads
			(clearance 0)
		)
		(min_thickness 0.25)
		(keepout
			(tracks allowed)
			(vias allowed)
			(pads allowed)
			(copperpour allowed)
			(footprints allowed)
		)
		(placement
			(enabled no)
			(sheetname "")
		)
		(fill
			(thermal_gap 0.5)
			(thermal_bridge_width 0.5)
			(island_removal_mode 0)
		)
		(polygon
			(pts
				(xy 207.154526 -298.77639) (xy 209.186526 -298.77639) (xy 209.186526 -299.00499) (xy 207.154526 -299.00499)
				(xy 207.018382 -299.00499) (xy 206.971392 -299.00499) (xy 206.971392 -298.77639) (xy 207.018382 -298.77639)
			)
		)
	)
	(zone
		(layer "F.Cu")
		(hatch none 0.5)
		(connect_pads
			(clearance 0)
		)
		(min_thickness 0.25)
		(keepout
			(tracks allowed)
			(vias allowed)
			(pads allowed)
			(copperpour allowed)
			(footprints allowed)
		)
		(placement
			(enabled no)
			(sheetname "")
		)
		(fill
			(thermal_gap 0.5)
			(thermal_bridge_width 0.5)
			(island_removal_mode 0)
		)
		(polygon
			(pts
				(xy 292.67531 -267.66647) (xy 292.67531 -267.222732) (xy 295.000426 -267.222732) (xy 295.000426 -267.66647)
			)
		)
	)
	(zone
		(layer "F.Cu")
		(hatch none 0.5)
		(connect_pads
			(clearance 0)
		)
		(min_thickness 0.25)
		(keepout
			(tracks allowed)
			(vias allowed)
			(pads allowed)
			(copperpour allowed)
			(footprints allowed)
		)
		(placement
			(enabled no)
			(sheetname "")
		)
		(fill
			(thermal_gap 0.5)
			(thermal_bridge_width 0.5)
			(island_removal_mode 0)
		)
		(polygon
			(pts
				(xy 259.056378 -300.816518) (xy 259.056378 -300.37278) (xy 261.381494 -300.37278) (xy 261.381494 -300.816518)
			)
		)
	)
	(zone
		(layer "F.Cu")
		(hatch none 0.5)
		(connect_pads
			(clearance 0)
		)
		(min_thickness 0.25)
		(keepout
			(tracks allowed)
			(vias allowed)
			(pads allowed)
			(copperpour allowed)
			(footprints allowed)
		)
		(placement
			(enabled no)
			(sheetname "")
		)
		(fill
			(thermal_gap 0.5)
			(thermal_bridge_width 0.5)
			(island_removal_mode 0)
		)
		(polygon
			(pts
				(xy 384.8735 -284.919928) (xy 385.16052 -284.919928) (xy 385.191 -284.889448) (xy 385.191 -284.262068)
				(xy 385.10464 -284.175708) (xy 384.91668 -284.175708) (xy 384.84302 -284.249368) (xy 384.84302 -284.889448)
			)
		)
	)
	(zone
		(layer "F.Cu")
		(hatch none 0.5)
		(connect_pads
			(clearance 0)
		)
		(min_thickness 0.25)
		(keepout
			(tracks allowed)
			(vias allowed)
			(pads allowed)
			(copperpour allowed)
			(footprints allowed)
		)
		(placement
			(enabled no)
			(sheetname "")
		)
		(fill
			(thermal_gap 0.5)
			(thermal_bridge_width 0.5)
			(island_removal_mode 0)
		)
		(polygon
			(pts
				(xy 209.186526 -269.026386) (xy 209.186526 -269.254986) (xy 209.316828 -269.254986) (xy 209.316828 -269.66164)
				(xy 206.95031 -269.66164) (xy 206.95031 -268.551152) (xy 209.186526 -268.551152)
			)
		)
	)
	(zone
		(layer "F.Cu")
		(hatch none 0.5)
		(connect_pads
			(clearance 0)
		)
		(min_thickness 0.25)
		(keepout
			(tracks allowed)
			(vias allowed)
			(pads allowed)
			(copperpour allowed)
			(footprints allowed)
		)
		(placement
			(enabled no)
			(sheetname "")
		)
		(fill
			(thermal_gap 0.5)
			(thermal_bridge_width 0.5)
			(island_removal_mode 0)
		)
		(polygon
			(pts
				(xy 14.560042 -202.216512) (xy 14.560042 -201.772774) (xy 16.885158 -201.772774) (xy 16.885158 -202.216512)
			)
		)
	)
	(zone
		(layer "F.Cu")
		(hatch none 0.5)
		(connect_pads
			(clearance 0)
		)
		(min_thickness 0.25)
		(keepout
			(tracks allowed)
			(vias allowed)
			(pads allowed)
			(copperpour allowed)
			(footprints allowed)
		)
		(placement
			(enabled no)
			(sheetname "")
		)
		(fill
			(thermal_gap 0.5)
			(thermal_bridge_width 0.5)
			(island_removal_mode 0)
		)
		(polygon
			(pts
				(xy 409.831794 -203.805028) (xy 409.831794 -203.576428) (xy 411.863794 -203.576428) (xy 411.863794 -203.805028)
			)
		)
	)
	(zone
		(layer "F.Cu")
		(hatch none 0.5)
		(connect_pads
			(clearance 0)
		)
		(min_thickness 0.25)
		(keepout
			(tracks allowed)
			(vias allowed)
			(pads allowed)
			(copperpour allowed)
			(footprints allowed)
		)
		(placement
			(enabled no)
			(sheetname "")
		)
		(fill
			(thermal_gap 0.5)
			(thermal_bridge_width 0.5)
			(island_removal_mode 0)
		)
		(polygon
			(pts
				(xy 161.891726 -316.004956) (xy 161.891726 -315.776356) (xy 163.923726 -315.776356) (xy 163.923726 -316.004956)
			)
		)
	)
	(zone
		(layer "F.Cu")
		(hatch none 0.5)
		(connect_pads
			(clearance 0)
		)
		(min_thickness 0.25)
		(keepout
			(tracks allowed)
			(vias allowed)
			(pads allowed)
			(copperpour allowed)
			(footprints allowed)
		)
		(placement
			(enabled no)
			(sheetname "")
		)
		(fill
			(thermal_gap 0.5)
			(thermal_bridge_width 0.5)
			(island_removal_mode 0)
		)
		(polygon
			(pts
				(xy 262.50011 -302.51654) (xy 262.50011 -302.072802) (xy 264.825226 -302.072802) (xy 264.825226 -302.51654)
			)
		)
	)
	(zone
		(layer "F.Cu")
		(hatch none 0.5)
		(connect_pads
			(clearance 0)
		)
		(min_thickness 0.25)
		(keepout
			(tracks allowed)
			(vias allowed)
			(pads allowed)
			(copperpour allowed)
			(footprints allowed)
		)
		(placement
			(enabled no)
			(sheetname "")
		)
		(fill
			(thermal_gap 0.5)
			(thermal_bridge_width 0.5)
			(island_removal_mode 0)
		)
		(polygon
			(pts
				(xy 274.143978 -228.566472) (xy 274.143978 -228.122734) (xy 276.469094 -228.122734) (xy 276.469094 -228.566472)
			)
		)
	)
	(zone
		(layer "F.Cu")
		(hatch none 0.5)
		(connect_pads
			(clearance 0)
		)
		(min_thickness 0.25)
		(keepout
			(tracks allowed)
			(vias allowed)
			(pads allowed)
			(copperpour allowed)
			(footprints allowed)
		)
		(placement
			(enabled no)
			(sheetname "")
		)
		(fill
			(thermal_gap 0.5)
			(thermal_bridge_width 0.5)
			(island_removal_mode 0)
		)
		(polygon
			(pts
				(xy 161.891726 -202.105006) (xy 161.891726 -201.876406) (xy 163.923726 -201.876406) (xy 163.923726 -202.105006)
			)
		)
	)
	(zone
		(layer "F.Cu")
		(hatch none 0.5)
		(connect_pads
			(clearance 0)
		)
		(min_thickness 0.25)
		(keepout
			(tracks allowed)
			(vias allowed)
			(pads allowed)
			(copperpour allowed)
			(footprints allowed)
		)
		(placement
			(enabled no)
			(sheetname "")
		)
		(fill
			(thermal_gap 0.5)
			(thermal_bridge_width 0.5)
			(island_removal_mode 0)
		)
		(polygon
			(pts
				(xy 157.791658 -283.704792) (xy 157.791658 -283.476192) (xy 159.823658 -283.476192) (xy 159.823658 -283.704792)
			)
		)
	)
	(zone
		(layer "F.Cu")
		(hatch none 0.5)
		(connect_pads
			(clearance 0)
		)
		(min_thickness 0.25)
		(keepout
			(tracks allowed)
			(vias allowed)
			(pads allowed)
			(copperpour allowed)
			(footprints allowed)
		)
		(placement
			(enabled no)
			(sheetname "")
		)
		(fill
			(thermal_gap 0.5)
			(thermal_bridge_width 0.5)
			(island_removal_mode 0)
		)
		(polygon
			(pts
				(xy 202.83043 -268.51737) (xy 205.325472 -268.51737) (xy 205.325472 -269.254986) (xy 205.325472 -269.425674)
				(xy 202.697334 -269.425674) (xy 202.697334 -268.51737)
			)
		)
	)
	(zone
		(layer "F.Cu")
		(hatch none 0.5)
		(connect_pads
			(clearance 0)
		)
		(min_thickness 0.25)
		(keepout
			(tracks allowed)
			(vias allowed)
			(pads allowed)
			(copperpour allowed)
			(footprints not_allowed)
		)
		(placement
			(enabled no)
			(sheetname "")
		)
		(fill
			(thermal_gap 0.5)
			(thermal_bridge_width 0.5)
			(island_removal_mode 0)
		)
		(polygon
			(pts
				(xy 44.859702 -330.091796) (xy 50.959512 -330.091796) (xy 50.959512 -186.09183) (xy 44.859702 -186.09183)
			)
		)
	)
	(zone
		(layer "F.Cu")
		(hatch none 0.5)
		(connect_pads
			(clearance 0)
		)
		(min_thickness 0.25)
		(keepout
			(tracks allowed)
			(vias allowed)
			(pads allowed)
			(copperpour allowed)
			(footprints allowed)
		)
		(placement
			(enabled no)
			(sheetname "")
		)
		(fill
			(thermal_gap 0.5)
			(thermal_bridge_width 0.5)
			(island_removal_mode 0)
		)
		(polygon
			(pts
				(xy 440.006994 -201.876406) (xy 442.038994 -201.876406) (xy 442.038994 -202.105006) (xy 440.006994 -202.105006)
				(xy 439.87085 -202.105006) (xy 439.82386 -202.105006) (xy 439.82386 -201.876406) (xy 439.87085 -201.876406)
			)
		)
	)
	(zone
		(layer "F.Cu")
		(hatch none 0.5)
		(connect_pads
			(clearance 0)
		)
		(min_thickness 0.25)
		(keepout
			(tracks allowed)
			(vias allowed)
			(pads allowed)
			(copperpour allowed)
			(footprints allowed)
		)
		(placement
			(enabled no)
			(sheetname "")
		)
		(fill
			(thermal_gap 0.5)
			(thermal_bridge_width 0.5)
			(island_removal_mode 0)
		)
		(polygon
			(pts
				(xy 307.76291 -224.316544) (xy 307.76291 -223.872806) (xy 310.088026 -223.872806) (xy 310.088026 -224.316544)
			)
		)
	)
	(zone
		(layer "F.Cu")
		(hatch none 0.5)
		(connect_pads
			(clearance 0)
		)
		(min_thickness 0.25)
		(keepout
			(tracks allowed)
			(vias allowed)
			(pads allowed)
			(copperpour allowed)
			(footprints allowed)
		)
		(placement
			(enabled no)
			(sheetname "")
		)
		(fill
			(thermal_gap 0.5)
			(thermal_bridge_width 0.5)
			(island_removal_mode 0)
		)
		(polygon
			(pts
				(xy 375.375424 -410.948886) (xy 375.375424 -406.105868) (xy 377.25985 -406.105868) (xy 377.25985 -410.948886)
			)
		)
	)
	(zone
		(layer "F.Cu")
		(hatch none 0.5)
		(connect_pads
			(clearance 0)
		)
		(min_thickness 0.25)
		(keepout
			(tracks allowed)
			(vias allowed)
			(pads allowed)
			(copperpour allowed)
			(footprints allowed)
		)
		(placement
			(enabled no)
			(sheetname "")
		)
		(fill
			(thermal_gap 0.5)
			(thermal_bridge_width 0.5)
			(island_removal_mode 0)
		)
		(polygon
			(pts
				(xy 56.37911 -288.06648) (xy 56.37911 -287.622742) (xy 58.704226 -287.622742) (xy 58.704226 -288.06648)
			)
		)
	)
	(zone
		(layer "F.Cu")
		(hatch none 0.5)
		(connect_pads
			(clearance 0)
		)
		(min_thickness 0.25)
		(keepout
			(tracks allowed)
			(vias allowed)
			(pads allowed)
			(copperpour allowed)
			(footprints allowed)
		)
		(placement
			(enabled no)
			(sheetname "")
		)
		(fill
			(thermal_gap 0.5)
			(thermal_bridge_width 0.5)
			(island_removal_mode 0)
		)
		(polygon
			(pts
				(xy 383.52222 -287.391348) (xy 383.80924 -287.391348) (xy 383.83972 -287.360868) (xy 383.83972 -286.733488)
				(xy 383.75336 -286.647128) (xy 383.5654 -286.647128) (xy 383.49174 -286.720788) (xy 383.49174 -287.360868)
			)
		)
	)
	(zone
		(layer "F.Cu")
		(hatch none 0.5)
		(connect_pads
			(clearance 0)
		)
		(min_thickness 0.25)
		(keepout
			(tracks allowed)
			(vias allowed)
			(pads allowed)
			(copperpour allowed)
			(footprints allowed)
		)
		(placement
			(enabled no)
			(sheetname "")
		)
		(fill
			(thermal_gap 0.5)
			(thermal_bridge_width 0.5)
			(island_removal_mode 0)
		)
		(polygon
			(pts
				(xy 409.831794 -197.854824) (xy 409.831794 -197.626224) (xy 411.863794 -197.626224) (xy 411.863794 -197.854824)
			)
		)
	)
	(zone
		(layer "F.Cu")
		(hatch none 0.5)
		(connect_pads
			(clearance 0)
		)
		(min_thickness 0.25)
		(keepout
			(tracks allowed)
			(vias allowed)
			(pads allowed)
			(copperpour allowed)
			(footprints allowed)
		)
		(placement
			(enabled no)
			(sheetname "")
		)
		(fill
			(thermal_gap 0.5)
			(thermal_bridge_width 0.5)
			(island_removal_mode 0)
		)
		(polygon
			(pts
				(xy 207.154526 -306.426362) (xy 209.186526 -306.426362) (xy 209.186526 -306.654962) (xy 207.154526 -306.654962)
				(xy 207.018382 -306.654962) (xy 206.971392 -306.654962) (xy 206.971392 -306.426362) (xy 207.018382 -306.426362)
			)
		)
	)
	(zone
		(layer "F.Cu")
		(hatch none 0.5)
		(connect_pads
			(clearance 0)
		)
		(min_thickness 0.25)
		(keepout
			(tracks allowed)
			(vias allowed)
			(pads allowed)
			(copperpour allowed)
			(footprints allowed)
		)
		(placement
			(enabled no)
			(sheetname "")
		)
		(fill
			(thermal_gap 0.5)
			(thermal_bridge_width 0.5)
			(island_removal_mode 0)
		)
		(polygon
			(pts
				(xy 195.510658 -252.25502) (xy 195.510658 -252.02642) (xy 197.542658 -252.02642) (xy 197.542658 -252.25502)
			)
		)
	)
	(zone
		(layer "F.Cu")
		(hatch none 0.5)
		(connect_pads
			(clearance 0)
		)
		(min_thickness 0.25)
		(keepout
			(tracks allowed)
			(vias allowed)
			(pads allowed)
			(copperpour allowed)
			(footprints allowed)
		)
		(placement
			(enabled no)
			(sheetname "")
		)
		(fill
			(thermal_gap 0.5)
			(thermal_bridge_width 0.5)
			(island_removal_mode 0)
		)
		(polygon
			(pts
				(xy 440.006994 -309.826406) (xy 442.038994 -309.826406) (xy 442.038994 -310.055006) (xy 440.006994 -310.055006)
				(xy 439.87085 -310.055006) (xy 439.82386 -310.055006) (xy 439.82386 -309.826406) (xy 439.87085 -309.826406)
			)
		)
	)
	(zone
		(layer "F.Cu")
		(hatch none 0.5)
		(connect_pads
			(clearance 0)
		)
		(min_thickness 0.25)
		(keepout
			(tracks allowed)
			(vias allowed)
			(pads allowed)
			(copperpour allowed)
			(footprints not_allowed)
		)
		(placement
			(enabled no)
			(sheetname "")
		)
		(fill
			(thermal_gap 0.5)
			(thermal_bridge_width 0.5)
			(island_removal_mode 0)
		)
		(polygon
			(pts
				(arc
					(start 94.383098 -50.25009)
					(mid 97.58299 -47.050198)
					(end 94.383098 -43.850052)
				)
				(arc
					(start 92.782898 -43.850052)
					(mid 89.582752 -47.050198)
					(end 92.782898 -50.25009)
				)
			)
		)
	)
	(zone
		(layer "F.Cu")
		(hatch none 0.5)
		(connect_pads
			(clearance 0)
		)
		(min_thickness 0.25)
		(keepout
			(tracks allowed)
			(vias allowed)
			(pads allowed)
			(copperpour allowed)
			(footprints allowed)
		)
		(placement
			(enabled no)
			(sheetname "")
		)
		(fill
			(thermal_gap 0.5)
			(thermal_bridge_width 0.5)
			(island_removal_mode 0)
		)
		(polygon
			(pts
				(xy 87.1728 -286.593788) (xy 87.45982 -286.593788) (xy 87.4903 -286.563308) (xy 87.4903 -285.935928)
				(xy 87.40394 -285.849568) (xy 87.21598 -285.849568) (xy 87.14232 -285.923228) (xy 87.14232 -286.563308)
			)
		)
	)
	(zone
		(layer "F.Cu")
		(hatch none 0.5)
		(connect_pads
			(clearance 0)
		)
		(min_thickness 0.25)
		(keepout
			(tracks allowed)
			(vias allowed)
			(pads allowed)
			(copperpour allowed)
			(footprints allowed)
		)
		(placement
			(enabled no)
			(sheetname "")
		)
		(fill
			(thermal_gap 0.5)
			(thermal_bridge_width 0.5)
			(island_removal_mode 0)
		)
		(polygon
			(pts
				(xy 440.006994 -222.276416) (xy 442.038994 -222.276416) (xy 442.038994 -222.505016) (xy 440.006994 -222.505016)
				(xy 439.87085 -222.505016) (xy 439.82386 -222.505016) (xy 439.82386 -222.276416) (xy 439.87085 -222.276416)
			)
		)
	)
	(zone
		(layer "F.Cu")
		(hatch none 0.5)
		(connect_pads
			(clearance 0)
		)
		(min_thickness 0.25)
		(keepout
			(tracks allowed)
			(vias allowed)
			(pads allowed)
			(copperpour allowed)
			(footprints allowed)
		)
		(placement
			(enabled no)
			(sheetname "")
		)
		(fill
			(thermal_gap 0.5)
			(thermal_bridge_width 0.5)
			(island_removal_mode 0)
		)
		(polygon
			(pts
				(xy 210.598258 -224.204784) (xy 210.598258 -223.976184) (xy 212.630258 -223.976184) (xy 212.630258 -224.204784)
			)
		)
	)
	(zone
		(layer "F.Cu")
		(hatch none 0.5)
		(connect_pads
			(clearance 0)
		)
		(min_thickness 0.25)
		(keepout
			(tracks allowed)
			(vias allowed)
			(pads allowed)
			(copperpour allowed)
			(footprints allowed)
		)
		(placement
			(enabled no)
			(sheetname "")
		)
		(fill
			(thermal_gap 0.5)
			(thermal_bridge_width 0.5)
			(island_removal_mode 0)
		)
		(polygon
			(pts
				(xy 44.735242 -252.366526) (xy 44.735242 -251.922788) (xy 47.060358 -251.922788) (xy 47.060358 -252.366526)
			)
		)
	)
	(zone
		(layer "F.Cu")
		(hatch none 0.5)
		(connect_pads
			(clearance 0)
		)
		(min_thickness 0.25)
		(keepout
			(tracks allowed)
			(vias allowed)
			(pads allowed)
			(copperpour allowed)
			(footprints allowed)
		)
		(placement
			(enabled no)
			(sheetname "")
		)
		(fill
			(thermal_gap 0.5)
			(thermal_bridge_width 0.5)
			(island_removal_mode 0)
		)
		(polygon
			(pts
				(xy 176.979326 -233.326432) (xy 179.011326 -233.326432) (xy 179.011326 -233.555032) (xy 176.979326 -233.555032)
				(xy 176.843182 -233.555032) (xy 176.796192 -233.555032) (xy 176.796192 -233.326432) (xy 176.843182 -233.326432)
			)
		)
	)
	(zone
		(layer "F.Cu")
		(hatch none 0.5)
		(connect_pads
			(clearance 0)
		)
		(min_thickness 0.25)
		(keepout
			(tracks allowed)
			(vias allowed)
			(pads allowed)
			(copperpour allowed)
			(footprints not_allowed)
		)
		(placement
			(enabled no)
			(sheetname "")
		)
		(fill
			(thermal_gap 0.5)
			(thermal_bridge_width 0.5)
			(island_removal_mode 0)
		)
		(polygon
			(pts
				(xy 351.94494 -261.62) (xy 355.575108 -261.62) (xy 355.575108 -237.00994) (xy 351.94494 -237.00994)
			)
		)
	)
	(zone
		(layer "F.Cu")
		(hatch none 0.5)
		(connect_pads
			(clearance 0)
		)
		(min_thickness 0.25)
		(keepout
			(tracks allowed)
			(vias allowed)
			(pads allowed)
			(copperpour allowed)
			(footprints allowed)
		)
		(placement
			(enabled no)
			(sheetname "")
		)
		(fill
			(thermal_gap 0.5)
			(thermal_bridge_width 0.5)
			(island_removal_mode 0)
		)
		(polygon
			(pts
				(xy 192.066926 -285.176214) (xy 194.098926 -285.176214) (xy 194.098926 -285.404814) (xy 192.066926 -285.404814)
				(xy 191.935608 -285.404814) (xy 191.9097 -285.404814) (xy 191.9097 -285.176214) (xy 191.935608 -285.176214)
			)
		)
	)
	(zone
		(layer "F.Cu")
		(hatch none 0.5)
		(connect_pads
			(clearance 0)
		)
		(min_thickness 0.25)
		(keepout
			(tracks allowed)
			(vias allowed)
			(pads allowed)
			(copperpour allowed)
			(footprints allowed)
		)
		(placement
			(enabled no)
			(sheetname "")
		)
		(fill
			(thermal_gap 0.5)
			(thermal_bridge_width 0.5)
			(island_removal_mode 0)
		)
		(polygon
			(pts
				(xy 210.598258 -267.554964) (xy 210.598258 -267.326364) (xy 212.630258 -267.326364) (xy 212.630258 -267.554964)
			)
		)
	)
	(zone
		(layer "F.Cu")
		(hatch none 0.5)
		(connect_pads
			(clearance 0)
		)
		(min_thickness 0.25)
		(keepout
			(tracks allowed)
			(vias allowed)
			(pads allowed)
			(copperpour allowed)
			(footprints allowed)
		)
		(placement
			(enabled no)
			(sheetname "")
		)
		(fill
			(thermal_gap 0.5)
			(thermal_bridge_width 0.5)
			(island_removal_mode 0)
		)
		(polygon
			(pts
				(xy 413.275526 -198.704962) (xy 413.275526 -198.476362) (xy 415.307526 -198.476362) (xy 415.307526 -198.704962)
			)
		)
	)
	(zone
		(layer "F.Cu")
		(hatch none 0.5)
		(connect_pads
			(clearance 0)
		)
		(min_thickness 0.25)
		(keepout
			(tracks allowed)
			(vias allowed)
			(pads allowed)
			(copperpour allowed)
			(footprints allowed)
		)
		(placement
			(enabled no)
			(sheetname "")
		)
		(fill
			(thermal_gap 0.5)
			(thermal_bridge_width 0.5)
			(island_removal_mode 0)
		)
		(polygon
			(pts
				(xy 270.04391 -268.516354) (xy 270.04391 -268.072616) (xy 270.04391 -267.659358) (xy 270.10741 -267.595858)
				(xy 272.402808 -267.595858) (xy 272.53565 -267.7287) (xy 272.53565 -268.467332) (xy 272.486628 -268.516354)
				(xy 272.369026 -268.516354)
			)
		)
	)
	(zone
		(layer "F.Cu")
		(hatch none 0.5)
		(connect_pads
			(clearance 0)
		)
		(min_thickness 0.25)
		(keepout
			(tracks allowed)
			(vias allowed)
			(pads allowed)
			(copperpour allowed)
			(footprints allowed)
		)
		(placement
			(enabled no)
			(sheetname "")
		)
		(fill
			(thermal_gap 0.5)
			(thermal_bridge_width 0.5)
			(island_removal_mode 0)
		)
		(polygon
			(pts
				(xy 207.154526 -195.926456) (xy 209.186526 -195.926456) (xy 209.186526 -196.155056) (xy 207.154526 -196.155056)
				(xy 207.018382 -196.155056) (xy 206.971392 -196.155056) (xy 206.971392 -195.926456) (xy 207.018382 -195.926456)
			)
		)
	)
	(zone
		(layer "F.Cu")
		(hatch none 0.5)
		(connect_pads
			(clearance 0)
		)
		(min_thickness 0.25)
		(keepout
			(tracks not_allowed)
			(vias allowed)
			(pads allowed)
			(copperpour not_allowed)
			(footprints allowed)
		)
		(placement
			(enabled no)
			(sheetname "")
		)
		(fill
			(thermal_gap 0.5)
			(thermal_bridge_width 0.5)
			(island_removal_mode 0)
		)
		(polygon
			(pts
				(arc
					(start 230.89997 -81.700116)
					(mid 235.89996 -76.700126)
					(end 240.89995 -81.700116)
				)
				(arc
					(start 240.89995 -81.700116)
					(mid 235.89996 -86.700106)
					(end 230.89997 -81.700116)
				)
			)
		)
	)
	(zone
		(layer "F.Cu")
		(hatch none 0.5)
		(connect_pads
			(clearance 0)
		)
		(min_thickness 0.25)
		(keepout
			(tracks allowed)
			(vias allowed)
			(pads allowed)
			(copperpour allowed)
			(footprints allowed)
		)
		(placement
			(enabled no)
			(sheetname "")
		)
		(fill
			(thermal_gap 0.5)
			(thermal_bridge_width 0.5)
			(island_removal_mode 0)
		)
		(polygon
			(pts
				(xy 11.11631 -239.616488) (xy 11.11631 -239.17275) (xy 13.441426 -239.17275) (xy 13.441426 -239.616488)
			)
		)
	)
	(zone
		(layer "F.Cu")
		(hatch none 0.5)
		(connect_pads
			(clearance 0)
		)
		(min_thickness 0.25)
		(keepout
			(tracks allowed)
			(vias allowed)
			(pads allowed)
			(copperpour allowed)
			(footprints allowed)
		)
		(placement
			(enabled no)
			(sheetname "")
		)
		(fill
			(thermal_gap 0.5)
			(thermal_bridge_width 0.5)
			(island_removal_mode 0)
		)
		(polygon
			(pts
				(xy 41.29151 -259.166614) (xy 41.29151 -258.722876) (xy 43.616626 -258.722876) (xy 43.616626 -259.166614)
			)
		)
	)
	(zone
		(layer "F.Cu")
		(hatch none 0.5)
		(connect_pads
			(clearance 0)
		)
		(min_thickness 0.25)
		(keepout
			(tracks allowed)
			(vias allowed)
			(pads allowed)
			(copperpour allowed)
			(footprints allowed)
		)
		(placement
			(enabled no)
			(sheetname "")
		)
		(fill
			(thermal_gap 0.5)
			(thermal_bridge_width 0.5)
			(island_removal_mode 0)
		)
		(polygon
			(pts
				(xy 304.319178 -196.266562) (xy 304.319178 -195.822824) (xy 306.644294 -195.822824) (xy 306.644294 -196.266562)
			)
		)
	)
	(zone
		(layer "F.Cu")
		(hatch none 0.5)
		(connect_pads
			(clearance 0)
		)
		(min_thickness 0.25)
		(keepout
			(tracks allowed)
			(vias allowed)
			(pads allowed)
			(copperpour allowed)
			(footprints not_allowed)
		)
		(placement
			(enabled no)
			(sheetname "")
		)
		(fill
			(thermal_gap 0.5)
			(thermal_bridge_width 0.5)
			(island_removal_mode 0)
		)
		(polygon
			(pts
				(xy 387.08711 -12.850114) (xy 456.727052 -12.850114)
				(arc
					(start 456.727052 -12.392406)
					(mid 455.61117 -11.292493)
					(end 455.202036 -9.780016)
				)
				(xy 455.202036 -0.999998) (xy 388.601966 -0.999998)
				(arc
					(start 388.601966 -9.780016)
					(mid 388.195735 -11.287382)
					(end 387.08711 -12.386564)
				)
			)
		)
	)
	(zone
		(layer "F.Cu")
		(hatch none 0.5)
		(connect_pads
			(clearance 0)
		)
		(min_thickness 0.25)
		(keepout
			(tracks allowed)
			(vias allowed)
			(pads allowed)
			(copperpour allowed)
			(footprints allowed)
		)
		(placement
			(enabled no)
			(sheetname "")
		)
		(fill
			(thermal_gap 0.5)
			(thermal_bridge_width 0.5)
			(island_removal_mode 0)
		)
		(polygon
			(pts
				(xy 424.919394 -229.07625) (xy 426.951394 -229.07625) (xy 426.951394 -229.30485) (xy 424.919394 -229.30485)
				(xy 424.788076 -229.30485) (xy 424.762168 -229.30485) (xy 424.762168 -229.07625) (xy 424.788076 -229.07625)
			)
		)
	)
	(zone
		(layer "F.Cu")
		(hatch none 0.5)
		(connect_pads
			(clearance 0)
		)
		(min_thickness 0.25)
		(keepout
			(tracks allowed)
			(vias allowed)
			(pads allowed)
			(copperpour allowed)
			(footprints allowed)
		)
		(placement
			(enabled no)
			(sheetname "")
		)
		(fill
			(thermal_gap 0.5)
			(thermal_bridge_width 0.5)
			(island_removal_mode 0)
		)
		(polygon
			(pts
				(xy 385.731766 -345.159838) (xy 383.984246 -345.159838) (xy 383.984246 -343.224358) (xy 385.731766 -343.224358)
			)
		)
	)
	(zone
		(layer "F.Cu")
		(hatch none 0.5)
		(connect_pads
			(clearance 0)
		)
		(min_thickness 0.25)
		(keepout
			(tracks allowed)
			(vias allowed)
			(pads allowed)
			(copperpour allowed)
			(footprints allowed)
		)
		(placement
			(enabled no)
			(sheetname "")
		)
		(fill
			(thermal_gap 0.5)
			(thermal_bridge_width 0.5)
			(island_removal_mode 0)
		)
		(polygon
			(pts
				(xy 37.76726 -12.918948) (xy 37.76726 -10.577068) (xy 46.16958 -10.577068) (xy 46.16958 -12.918948)
			)
		)
	)
	(zone
		(layer "F.Cu")
		(hatch none 0.5)
		(connect_pads
			(clearance 0)
		)
		(min_thickness 0.25)
		(keepout
			(tracks allowed)
			(vias allowed)
			(pads allowed)
			(copperpour allowed)
			(footprints allowed)
		)
		(placement
			(enabled no)
			(sheetname "")
		)
		(fill
			(thermal_gap 0.5)
			(thermal_bridge_width 0.5)
			(island_removal_mode 0)
		)
		(polygon
			(pts
				(xy 277.58771 -295.716452) (xy 277.58771 -295.272714) (xy 279.912826 -295.272714) (xy 279.912826 -295.716452)
			)
		)
	)
	(zone
		(layer "F.Cu")
		(hatch none 0.5)
		(connect_pads
			(clearance 0)
		)
		(min_thickness 0.25)
		(keepout
			(tracks allowed)
			(vias allowed)
			(pads allowed)
			(copperpour allowed)
			(footprints not_allowed)
		)
		(placement
			(enabled no)
			(sheetname "")
		)
		(fill
			(thermal_gap 0.5)
			(thermal_bridge_width 0.5)
			(island_removal_mode 0)
		)
		(polygon
			(pts
				(arc
					(start 97.700338 -435.600094)
					(mid 100.500434 -432.799998)
					(end 103.300276 -435.600094)
				)
				(arc
					(start 103.300276 -435.600094)
					(mid 100.500434 -438.399936)
					(end 97.700338 -435.600094)
				)
			)
		)
	)
	(zone
		(layer "F.Cu")
		(hatch none 0.5)
		(connect_pads
			(clearance 0)
		)
		(min_thickness 0.25)
		(keepout
			(tracks allowed)
			(vias allowed)
			(pads allowed)
			(copperpour allowed)
			(footprints allowed)
		)
		(placement
			(enabled no)
			(sheetname "")
		)
		(fill
			(thermal_gap 0.5)
			(thermal_bridge_width 0.5)
			(island_removal_mode 0)
		)
		(polygon
			(pts
				(xy 409.831794 -266.704826) (xy 409.831794 -266.476226) (xy 411.863794 -266.476226) (xy 411.863794 -266.704826)
			)
		)
	)
	(zone
		(layer "F.Cu")
		(hatch none 0.5)
		(connect_pads
			(clearance 0)
		)
		(min_thickness 0.25)
		(keepout
			(tracks allowed)
			(vias allowed)
			(pads allowed)
			(copperpour allowed)
			(footprints allowed)
		)
		(placement
			(enabled no)
			(sheetname "")
		)
		(fill
			(thermal_gap 0.5)
			(thermal_bridge_width 0.5)
			(island_removal_mode 0)
		)
		(polygon
			(pts
				(xy 409.831794 -205.504796) (xy 409.831794 -205.276196) (xy 411.863794 -205.276196) (xy 411.863794 -205.504796)
			)
		)
	)
	(zone
		(layer "F.Cu")
		(hatch none 0.5)
		(connect_pads
			(clearance 0)
		)
		(min_thickness 0.25)
		(keepout
			(tracks allowed)
			(vias allowed)
			(pads allowed)
			(copperpour allowed)
			(footprints allowed)
		)
		(placement
			(enabled no)
			(sheetname "")
		)
		(fill
			(thermal_gap 0.5)
			(thermal_bridge_width 0.5)
			(island_removal_mode 0)
		)
		(polygon
			(pts
				(xy 289.231578 -248.966482) (xy 289.231578 -248.522744) (xy 291.556694 -248.522744) (xy 291.556694 -248.966482)
			)
		)
	)
	(zone
		(layer "F.Cu")
		(hatch none 0.5)
		(connect_pads
			(clearance 0)
		)
		(min_thickness 0.25)
		(keepout
			(tracks allowed)
			(vias allowed)
			(pads allowed)
			(copperpour allowed)
			(footprints allowed)
		)
		(placement
			(enabled no)
			(sheetname "")
		)
		(fill
			(thermal_gap 0.5)
			(thermal_bridge_width 0.5)
			(island_removal_mode 0)
		)
		(polygon
			(pts
				(xy 192.066926 -306.426362) (xy 194.098926 -306.426362) (xy 194.098926 -306.654962) (xy 192.066926 -306.654962)
				(xy 191.930782 -306.654962) (xy 191.883792 -306.654962) (xy 191.883792 -306.426362) (xy 191.930782 -306.426362)
			)
		)
	)
	(zone
		(layer "F.Cu")
		(hatch none 0.5)
		(connect_pads
			(clearance 0)
		)
		(min_thickness 0.25)
		(keepout
			(tracks allowed)
			(vias allowed)
			(pads allowed)
			(copperpour allowed)
			(footprints allowed)
		)
		(placement
			(enabled no)
			(sheetname "")
		)
		(fill
			(thermal_gap 0.5)
			(thermal_bridge_width 0.5)
			(island_removal_mode 0)
		)
		(polygon
			(pts
				(xy 14.560042 -215.816434) (xy 14.560042 -215.372696) (xy 16.885158 -215.372696) (xy 16.885158 -215.816434)
			)
		)
	)
	(zone
		(layer "F.Cu")
		(hatch none 0.5)
		(connect_pads
			(clearance 0)
		)
		(min_thickness 0.25)
		(keepout
			(tracks allowed)
			(vias allowed)
			(pads allowed)
			(copperpour allowed)
			(footprints allowed)
		)
		(placement
			(enabled no)
			(sheetname "")
		)
		(fill
			(thermal_gap 0.5)
			(thermal_bridge_width 0.5)
			(island_removal_mode 0)
		)
		(polygon
			(pts
				(xy 207.154526 -200.407016) (xy 209.186526 -200.407016) (xy 209.186526 -200.178416) (xy 207.154526 -200.178416)
				(xy 207.023208 -200.178416) (xy 206.9973 -200.178416) (xy 206.9973 -200.407016) (xy 207.023208 -200.407016)
			)
		)
	)
	(zone
		(layer "F.Cu")
		(hatch none 0.5)
		(connect_pads
			(clearance 0)
		)
		(min_thickness 0.25)
		(keepout
			(tracks allowed)
			(vias allowed)
			(pads allowed)
			(copperpour allowed)
			(footprints allowed)
		)
		(placement
			(enabled no)
			(sheetname "")
		)
		(fill
			(thermal_gap 0.5)
			(thermal_bridge_width 0.5)
			(island_removal_mode 0)
		)
		(polygon
			(pts
				(xy 311.84088 -234.922822) (xy 314.17768 -234.922822) (xy 314.473844 -234.922822) (xy 314.473844 -235.848652)
				(xy 311.5183 -235.848652) (xy 311.5183 -234.922822)
			)
		)
	)
	(zone
		(layer "F.Cu")
		(hatch none 0.5)
		(connect_pads
			(clearance 0)
		)
		(min_thickness 0.25)
		(keepout
			(tracks allowed)
			(vias allowed)
			(pads allowed)
			(copperpour allowed)
			(footprints allowed)
		)
		(placement
			(enabled no)
			(sheetname "")
		)
		(fill
			(thermal_gap 0.5)
			(thermal_bridge_width 0.5)
			(island_removal_mode 0)
		)
		(polygon
			(pts
				(xy 180.423058 -247.154954) (xy 180.423058 -246.926354) (xy 182.455058 -246.926354) (xy 182.455058 -247.154954)
			)
		)
	)
	(zone
		(layer "F.Cu")
		(hatch none 0.5)
		(connect_pads
			(clearance 0)
		)
		(min_thickness 0.25)
		(keepout
			(tracks allowed)
			(vias allowed)
			(pads allowed)
			(copperpour allowed)
			(footprints not_allowed)
		)
		(placement
			(enabled no)
			(sheetname "")
		)
		(fill
			(thermal_gap 0.5)
			(thermal_bridge_width 0.5)
			(island_removal_mode 0)
		)
		(polygon
			(pts
				(xy 324.39991 -35.450018) (xy 336.849974 -35.450018) (xy 336.849974 -17.450054) (xy 307.999892 -17.450054)
				(arc
					(start 307.999892 -76.950062)
					(mid 308.732161 -78.717915)
					(end 310.500014 -79.44993)
				)
				(xy 316.850014 -79.44993)
				(arc
					(start 316.850014 -73.449688)
					(mid 316.900052 -63.442346)
					(end 316.95009 -73.449688)
				)
				(xy 316.95009 -79.44993) (xy 336.849974 -79.44993) (xy 336.849974 -61.449966) (xy 324.39991 -61.449966)
			)
		)
	)
	(zone
		(layer "F.Cu")
		(hatch none 0.5)
		(connect_pads
			(clearance 0)
		)
		(min_thickness 0.25)
		(keepout
			(tracks allowed)
			(vias allowed)
			(pads allowed)
			(copperpour allowed)
			(footprints allowed)
		)
		(placement
			(enabled no)
			(sheetname "")
		)
		(fill
			(thermal_gap 0.5)
			(thermal_bridge_width 0.5)
			(island_removal_mode 0)
		)
		(polygon
			(pts
				(xy 176.979326 -246.304816) (xy 176.979326 -246.076216) (xy 179.011326 -246.076216) (xy 179.011326 -246.304816)
			)
		)
	)
	(zone
		(layer "F.Cu")
		(hatch none 0.5)
		(connect_pads
			(clearance 0)
		)
		(min_thickness 0.25)
		(keepout
			(tracks allowed)
			(vias allowed)
			(pads allowed)
			(copperpour allowed)
			(footprints allowed)
		)
		(placement
			(enabled no)
			(sheetname "")
		)
		(fill
			(thermal_gap 0.5)
			(thermal_bridge_width 0.5)
			(island_removal_mode 0)
		)
		(polygon
			(pts
				(xy 230.71328 -130.444748) (xy 230.71328 -123.053348) (xy 239.17148 -123.053348) (xy 239.17148 -130.444748)
			)
		)
	)
	(zone
		(layer "F.Cu")
		(hatch none 0.5)
		(connect_pads
			(clearance 0)
		)
		(min_thickness 0.25)
		(keepout
			(tracks allowed)
			(vias allowed)
			(pads allowed)
			(copperpour allowed)
			(footprints allowed)
		)
		(placement
			(enabled no)
			(sheetname "")
		)
		(fill
			(thermal_gap 0.5)
			(thermal_bridge_width 0.5)
			(island_removal_mode 0)
		)
		(polygon
			(pts
				(xy 180.423058 -222.505016) (xy 180.423058 -222.276416) (xy 182.455058 -222.276416) (xy 182.455058 -222.505016)
			)
		)
	)
	(zone
		(layer "F.Cu")
		(hatch none 0.5)
		(connect_pads
			(clearance 0)
		)
		(min_thickness 0.25)
		(keepout
			(tracks allowed)
			(vias allowed)
			(pads allowed)
			(copperpour allowed)
			(footprints allowed)
		)
		(placement
			(enabled no)
			(sheetname "")
		)
		(fill
			(thermal_gap 0.5)
			(thermal_bridge_width 0.5)
			(island_removal_mode 0)
		)
		(polygon
			(pts
				(xy 26.20391 -240.872772) (xy 28.529026 -240.872772) (xy 28.598622 -240.872772) (xy 28.598622 -241.83213)
				(xy 26.069798 -241.83213) (xy 26.069798 -240.872772)
			)
		)
	)
	(zone
		(layer "F.Cu")
		(hatch none 0.5)
		(connect_pads
			(clearance 0)
		)
		(min_thickness 0.25)
		(keepout
			(tracks not_allowed)
			(vias allowed)
			(pads allowed)
			(copperpour not_allowed)
			(footprints allowed)
		)
		(placement
			(enabled no)
			(sheetname "")
		)
		(fill
			(thermal_gap 0.5)
			(thermal_bridge_width 0.5)
			(island_removal_mode 0)
		)
		(polygon
			(pts
				(xy 252.837188 -102.408736) (xy 258.528312 -102.408736) (xy 258.528312 -96.717612) (xy 253.44882 -96.717612)
				(xy 253.44882 -96.959674) (xy 258.28625 -96.959674) (xy 258.28625 -102.166674) (xy 253.39675 -102.166674)
				(xy 253.07925 -101.849174) (xy 253.07925 -101.341174) (xy 252.837188 -101.341174)
			)
		)
	)
	(zone
		(layer "F.Cu")
		(hatch none 0.5)
		(connect_pads
			(clearance 0)
		)
		(min_thickness 0.25)
		(keepout
			(tracks allowed)
			(vias allowed)
			(pads allowed)
			(copperpour allowed)
			(footprints allowed)
		)
		(placement
			(enabled no)
			(sheetname "")
		)
		(fill
			(thermal_gap 0.5)
			(thermal_bridge_width 0.5)
			(island_removal_mode 0)
		)
		(polygon
			(pts
				(xy 428.363126 -295.604946) (xy 428.363126 -295.376346) (xy 430.395126 -295.376346) (xy 430.395126 -295.604946)
			)
		)
	)
	(zone
		(layer "F.Cu")
		(hatch none 0.5)
		(connect_pads
			(clearance 0)
		)
		(min_thickness 0.25)
		(keepout
			(tracks allowed)
			(vias allowed)
			(pads allowed)
			(copperpour allowed)
			(footprints allowed)
		)
		(placement
			(enabled no)
			(sheetname "")
		)
		(fill
			(thermal_gap 0.5)
			(thermal_bridge_width 0.5)
			(island_removal_mode 0)
		)
		(polygon
			(pts
				(xy 304.319178 -282.11653) (xy 304.319178 -281.672792) (xy 306.644294 -281.672792) (xy 306.644294 -282.11653)
			)
		)
	)
	(zone
		(layer "F.Cu")
		(hatch none 0.5)
		(connect_pads
			(clearance 0)
		)
		(min_thickness 0.25)
		(keepout
			(tracks allowed)
			(vias allowed)
			(pads allowed)
			(copperpour allowed)
			(footprints allowed)
		)
		(placement
			(enabled no)
			(sheetname "")
		)
		(fill
			(thermal_gap 0.5)
			(thermal_bridge_width 0.5)
			(island_removal_mode 0)
		)
		(polygon
			(pts
				(xy 157.791658 -208.90484) (xy 157.791658 -208.67624) (xy 159.823658 -208.67624) (xy 159.823658 -208.90484)
			)
		)
	)
	(zone
		(layer "F.Cu")
		(hatch none 0.5)
		(connect_pads
			(clearance 0)
		)
		(min_thickness 0.25)
		(keepout
			(tracks allowed)
			(vias allowed)
			(pads allowed)
			(copperpour allowed)
			(footprints allowed)
		)
		(placement
			(enabled no)
			(sheetname "")
		)
		(fill
			(thermal_gap 0.5)
			(thermal_bridge_width 0.5)
			(island_removal_mode 0)
		)
		(polygon
			(pts
				(xy 165.335458 -310.055006) (xy 165.335458 -309.826406) (xy 167.367458 -309.826406) (xy 167.367458 -310.055006)
			)
		)
	)
	(zone
		(layer "F.Cu")
		(hatch none 0.5)
		(connect_pads
			(clearance 0)
		)
		(min_thickness 0.25)
		(keepout
			(tracks allowed)
			(vias allowed)
			(pads allowed)
			(copperpour allowed)
			(footprints allowed)
		)
		(placement
			(enabled no)
			(sheetname "")
		)
		(fill
			(thermal_gap 0.5)
			(thermal_bridge_width 0.5)
			(island_removal_mode 0)
		)
		(polygon
			(pts
				(xy 11.11631 -259.166614) (xy 11.11631 -258.722876) (xy 13.441426 -258.722876) (xy 13.441426 -259.166614)
			)
		)
	)
	(zone
		(layer "F.Cu")
		(hatch none 0.5)
		(connect_pads
			(clearance 0)
		)
		(min_thickness 0.25)
		(keepout
			(tracks not_allowed)
			(vias allowed)
			(pads allowed)
			(copperpour not_allowed)
			(footprints allowed)
		)
		(placement
			(enabled no)
			(sheetname "")
		)
		(fill
			(thermal_gap 0.5)
			(thermal_bridge_width 0.5)
			(island_removal_mode 0)
		)
		(polygon
			(pts
				(arc
					(start 241.650012 -192.499996)
					(mid 236.650022 -197.499986)
					(end 231.650032 -192.499996)
				)
				(arc
					(start 231.650032 -192.499996)
					(mid 236.650022 -187.500006)
					(end 241.650012 -192.499996)
				)
			)
		)
		(polygon
			(pts
				(arc
					(start 238.650018 -192.499996)
					(mid 236.650022 -194.499992)
					(end 234.650026 -192.499996)
				)
				(arc
					(start 234.650026 -192.499996)
					(mid 236.650022 -190.5)
					(end 238.650018 -192.499996)
				)
			)
		)
	)
	(zone
		(layer "F.Cu")
		(hatch none 0.5)
		(connect_pads
			(clearance 0)
		)
		(min_thickness 0.25)
		(keepout
			(tracks allowed)
			(vias allowed)
			(pads allowed)
			(copperpour allowed)
			(footprints allowed)
		)
		(placement
			(enabled no)
			(sheetname "")
		)
		(fill
			(thermal_gap 0.5)
			(thermal_bridge_width 0.5)
			(island_removal_mode 0)
		)
		(polygon
			(pts
				(xy 289.231578 -276.16658) (xy 289.231578 -275.722842) (xy 291.556694 -275.722842) (xy 291.556694 -276.16658)
			)
		)
	)
	(zone
		(layer "F.Cu")
		(hatch none 0.5)
		(connect_pads
			(clearance 0)
		)
		(min_thickness 0.25)
		(keepout
			(tracks allowed)
			(vias allowed)
			(pads allowed)
			(copperpour allowed)
			(footprints allowed)
		)
		(placement
			(enabled no)
			(sheetname "")
		)
		(fill
			(thermal_gap 0.5)
			(thermal_bridge_width 0.5)
			(island_removal_mode 0)
		)
		(polygon
			(pts
				(xy 415.318702 -270.95704) (xy 413.286702 -270.95704) (xy 413.286702 -270.954754) (xy 413.107886 -270.954754)
				(xy 413.107886 -270.717518) (xy 412.969964 -270.717518) (xy 412.926784 -270.674338) (xy 412.926784 -270.541496)
				(xy 412.926784 -270.237458) (xy 412.999428 -270.164814) (xy 415.539682 -270.164814) (xy 415.680906 -270.306038)
				(xy 415.680906 -270.503142) (xy 415.599372 -270.584676) (xy 415.599372 -270.95704) (xy 415.501836 -270.95704)
				(xy 415.454846 -270.95704)
			)
		)
	)
	(zone
		(layer "F.Cu")
		(hatch none 0.5)
		(connect_pads
			(clearance 0)
		)
		(min_thickness 0.25)
		(keepout
			(tracks allowed)
			(vias allowed)
			(pads allowed)
			(copperpour allowed)
			(footprints allowed)
		)
		(placement
			(enabled no)
			(sheetname "")
		)
		(fill
			(thermal_gap 0.5)
			(thermal_bridge_width 0.5)
			(island_removal_mode 0)
		)
		(polygon
			(pts
				(xy 11.11631 -220.9165) (xy 11.11631 -220.472762) (xy 13.441426 -220.472762) (xy 13.441426 -220.9165)
			)
		)
	)
	(zone
		(layer "F.Cu")
		(hatch none 0.5)
		(connect_pads
			(clearance 0)
		)
		(min_thickness 0.25)
		(keepout
			(tracks allowed)
			(vias allowed)
			(pads allowed)
			(copperpour allowed)
			(footprints allowed)
		)
		(placement
			(enabled no)
			(sheetname "")
		)
		(fill
			(thermal_gap 0.5)
			(thermal_bridge_width 0.5)
			(island_removal_mode 0)
		)
		(polygon
			(pts
				(xy 165.335458 -262.454898) (xy 165.335458 -262.226298) (xy 167.367458 -262.226298) (xy 167.367458 -262.454898)
			)
		)
	)
	(zone
		(layer "F.Cu")
		(hatch none 0.5)
		(connect_pads
			(clearance 0)
		)
		(min_thickness 0.25)
		(keepout
			(tracks not_allowed)
			(vias allowed)
			(pads allowed)
			(copperpour not_allowed)
			(footprints allowed)
		)
		(placement
			(enabled no)
			(sheetname "")
		)
		(fill
			(thermal_gap 0.5)
			(thermal_bridge_width 0.5)
			(island_removal_mode 0)
		)
		(polygon
			(pts
				(arc
					(start 110.3249 -431.360072)
					(mid 112.024922 -429.66005)
					(end 113.724944 -431.360072)
				)
				(arc
					(start 113.724944 -431.360072)
					(mid 112.024922 -433.060094)
					(end 110.3249 -431.360072)
				)
			)
		)
	)
	(zone
		(layer "F.Cu")
		(hatch none 0.5)
		(connect_pads
			(clearance 0)
		)
		(min_thickness 0.25)
		(keepout
			(tracks allowed)
			(vias allowed)
			(pads allowed)
			(copperpour allowed)
			(footprints allowed)
		)
		(placement
			(enabled no)
			(sheetname "")
		)
		(fill
			(thermal_gap 0.5)
			(thermal_bridge_width 0.5)
			(island_removal_mode 0)
		)
		(polygon
			(pts
				(xy 387.214364 -231.939592) (xy 387.41731 -231.736646) (xy 387.41731 -231.69372) (xy 386.973826 -231.249982)
				(xy 386.851652 -231.249982) (xy 386.718556 -231.382824) (xy 386.718556 -231.486964) (xy 387.171184 -231.939592)
			)
		)
	)
	(zone
		(layer "F.Cu")
		(hatch none 0.5)
		(connect_pads
			(clearance 0)
		)
		(min_thickness 0.25)
		(keepout
			(tracks allowed)
			(vias allowed)
			(pads allowed)
			(copperpour allowed)
			(footprints allowed)
		)
		(placement
			(enabled no)
			(sheetname "")
		)
		(fill
			(thermal_gap 0.5)
			(thermal_bridge_width 0.5)
			(island_removal_mode 0)
		)
		(polygon
			(pts
				(xy 136.915652 -342.109298) (xy 135.099552 -342.109298) (xy 135.099552 -340.730078) (xy 136.915652 -340.730078)
			)
		)
	)
	(zone
		(layer "F.Cu")
		(hatch none 0.5)
		(connect_pads
			(clearance 0)
		)
		(min_thickness 0.25)
		(keepout
			(tracks allowed)
			(vias allowed)
			(pads allowed)
			(copperpour allowed)
			(footprints not_allowed)
		)
		(placement
			(enabled no)
			(sheetname "")
		)
		(fill
			(thermal_gap 0.5)
			(thermal_bridge_width 0.5)
			(island_removal_mode 0)
		)
		(polygon
			(pts
				(xy 177.433224 -36.124896) (xy 169.283126 -36.124896) (xy 169.283126 -57.974992) (xy 177.433224 -57.974992)
			)
		)
	)
	(zone
		(layer "F.Cu")
		(hatch none 0.5)
		(connect_pads
			(clearance 0)
		)
		(min_thickness 0.25)
		(keepout
			(tracks allowed)
			(vias allowed)
			(pads allowed)
			(copperpour allowed)
			(footprints allowed)
		)
		(placement
			(enabled no)
			(sheetname "")
		)
		(fill
			(thermal_gap 0.5)
			(thermal_bridge_width 0.5)
			(island_removal_mode 0)
		)
		(polygon
			(pts
				(xy 455.094594 -289.426396) (xy 457.126594 -289.426396) (xy 457.126594 -289.654996) (xy 455.094594 -289.654996)
				(xy 454.95845 -289.654996) (xy 454.91146 -289.654996) (xy 454.91146 -289.426396) (xy 454.95845 -289.426396)
			)
		)
	)
	(zone
		(layer "F.Cu")
		(hatch none 0.5)
		(connect_pads
			(clearance 0)
		)
		(min_thickness 0.25)
		(keepout
			(tracks allowed)
			(vias allowed)
			(pads allowed)
			(copperpour allowed)
			(footprints allowed)
		)
		(placement
			(enabled no)
			(sheetname "")
		)
		(fill
			(thermal_gap 0.5)
			(thermal_bridge_width 0.5)
			(island_removal_mode 0)
		)
		(polygon
			(pts
				(xy 161.891726 -216.554812) (xy 161.891726 -216.326212) (xy 163.923726 -216.326212) (xy 163.923726 -216.554812)
			)
		)
	)
	(zone
		(layer "F.Cu")
		(hatch none 0.5)
		(connect_pads
			(clearance 0)
		)
		(min_thickness 0.25)
		(keepout
			(tracks allowed)
			(vias allowed)
			(pads allowed)
			(copperpour allowed)
			(footprints allowed)
		)
		(placement
			(enabled no)
			(sheetname "")
		)
		(fill
			(thermal_gap 0.5)
			(thermal_bridge_width 0.5)
			(island_removal_mode 0)
		)
		(polygon
			(pts
				(xy 262.50011 -231.116632) (xy 262.50011 -230.672894) (xy 264.825226 -230.672894) (xy 264.825226 -231.116632)
			)
		)
	)
	(zone
		(layer "F.Cu")
		(hatch none 0.5)
		(connect_pads
			(clearance 0)
		)
		(min_thickness 0.25)
		(keepout
			(tracks allowed)
			(vias allowed)
			(pads allowed)
			(copperpour allowed)
			(footprints allowed)
		)
		(placement
			(enabled no)
			(sheetname "")
		)
		(fill
			(thermal_gap 0.5)
			(thermal_bridge_width 0.5)
			(island_removal_mode 0)
		)
		(polygon
			(pts
				(xy 455.094594 -266.476226) (xy 457.126594 -266.476226) (xy 457.126594 -266.704826) (xy 455.094594 -266.704826)
				(xy 454.92797 -266.704826) (xy 454.833736 -266.704826) (xy 454.833736 -266.476226) (xy 454.92797 -266.476226)
			)
		)
	)
	(zone
		(layer "F.Cu")
		(hatch none 0.5)
		(connect_pads
			(clearance 0)
		)
		(min_thickness 0.25)
		(keepout
			(tracks allowed)
			(vias allowed)
			(pads allowed)
			(copperpour allowed)
			(footprints allowed)
		)
		(placement
			(enabled no)
			(sheetname "")
		)
		(fill
			(thermal_gap 0.5)
			(thermal_bridge_width 0.5)
			(island_removal_mode 0)
		)
		(polygon
			(pts
				(xy 165.335458 -217.40495) (xy 165.335458 -217.17635) (xy 167.367458 -217.17635) (xy 167.367458 -217.40495)
			)
		)
	)
	(zone
		(layer "F.Cu")
		(hatch none 0.5)
		(connect_pads
			(clearance 0)
		)
		(min_thickness 0.25)
		(keepout
			(tracks allowed)
			(vias allowed)
			(pads allowed)
			(copperpour allowed)
			(footprints allowed)
		)
		(placement
			(enabled no)
			(sheetname "")
		)
		(fill
			(thermal_gap 0.5)
			(thermal_bridge_width 0.5)
			(island_removal_mode 0)
		)
		(polygon
			(pts
				(xy 64.002412 -316.116462) (xy 64.002412 -315.672724) (xy 66.186812 -315.672724) (xy 66.186812 -316.116462)
			)
		)
	)
	(zone
		(layer "F.Cu")
		(hatch none 0.5)
		(connect_pads
			(clearance 0)
		)
		(min_thickness 0.25)
		(keepout
			(tracks allowed)
			(vias allowed)
			(pads allowed)
			(copperpour allowed)
			(footprints allowed)
		)
		(placement
			(enabled no)
			(sheetname "")
		)
		(fill
			(thermal_gap 0.5)
			(thermal_bridge_width 0.5)
			(island_removal_mode 0)
		)
		(polygon
			(pts
				(xy 159.834834 -270.95704) (xy 157.802834 -270.95704) (xy 157.802834 -270.954754) (xy 157.624018 -270.954754)
				(xy 157.624018 -270.717518) (xy 157.569916 -270.717518) (xy 157.442916 -270.590518) (xy 157.442916 -270.541496)
				(xy 157.442916 -270.237458) (xy 157.51556 -270.164814) (xy 160.055814 -270.164814) (xy 160.197038 -270.306038)
				(xy 160.197038 -270.503142) (xy 160.115504 -270.584676) (xy 160.017968 -270.682212) (xy 160.017968 -270.95704)
				(xy 159.970978 -270.95704)
			)
		)
	)
	(zone
		(layer "F.Cu")
		(hatch none 0.5)
		(connect_pads
			(clearance 0)
		)
		(min_thickness 0.25)
		(keepout
			(tracks allowed)
			(vias allowed)
			(pads allowed)
			(copperpour allowed)
			(footprints allowed)
		)
		(placement
			(enabled no)
			(sheetname "")
		)
		(fill
			(thermal_gap 0.5)
			(thermal_bridge_width 0.5)
			(island_removal_mode 0)
		)
		(polygon
			(pts
				(xy 176.979326 -205.27645) (xy 179.011326 -205.27645) (xy 179.011326 -205.50505) (xy 176.979326 -205.50505)
				(xy 176.843182 -205.50505) (xy 176.796192 -205.50505) (xy 176.796192 -205.27645) (xy 176.843182 -205.27645)
			)
		)
	)
	(zone
		(layer "F.Cu")
		(hatch none 0.5)
		(connect_pads
			(clearance 0)
		)
		(min_thickness 0.25)
		(keepout
			(tracks allowed)
			(vias allowed)
			(pads allowed)
			(copperpour allowed)
			(footprints allowed)
		)
		(placement
			(enabled no)
			(sheetname "")
		)
		(fill
			(thermal_gap 0.5)
			(thermal_bridge_width 0.5)
			(island_removal_mode 0)
		)
		(polygon
			(pts
				(xy 192.066926 -270.726408) (xy 194.098926 -270.726408) (xy 194.098926 -270.728694) (xy 194.277742 -270.728694)
				(xy 194.277742 -270.96593) (xy 194.415664 -270.96593) (xy 194.458844 -271.00911) (xy 194.458844 -271.141952)
				(xy 194.458844 -271.44599) (xy 194.3862 -271.518634) (xy 191.845946 -271.518634) (xy 191.704722 -271.37741)
				(xy 191.704722 -271.180306) (xy 191.786256 -271.098772) (xy 191.786256 -270.726408) (xy 191.883792 -270.726408)
				(xy 191.930782 -270.726408)
			)
		)
	)
	(zone
		(layer "F.Cu")
		(hatch none 0.5)
		(connect_pads
			(clearance 0)
		)
		(min_thickness 0.25)
		(keepout
			(tracks not_allowed)
			(vias allowed)
			(pads allowed)
			(copperpour not_allowed)
			(footprints allowed)
		)
		(placement
			(enabled no)
			(sheetname "")
		)
		(fill
			(thermal_gap 0.5)
			(thermal_bridge_width 0.5)
			(island_removal_mode 0)
		)
		(polygon
			(pts
				(xy 54.699154 -167.614092) (xy 54.948836 -167.614092) (xy 54.948836 -165.362128) (xy 54.93512 -165.362128)
				(xy 54.93512 -165.349428) (xy 54.71414 -165.349428) (xy 54.71414 -165.133528) (xy 54.65318 -165.133528)
				(xy 54.65318 -165.16604) (xy 52.59578 -165.16604) (xy 52.59578 -163.31184) (xy 52.836826 -163.31184)
				(xy 52.836826 -163.069524) (xy 52.355242 -163.069524) (xy 52.355242 -167.01262) (xy 52.540154 -166.827708)
				(xy 52.540154 -165.457378) (xy 54.699154 -165.457378)
			)
		)
	)
	(zone
		(layer "F.Cu")
		(hatch none 0.5)
		(connect_pads
			(clearance 0)
		)
		(min_thickness 0.25)
		(keepout
			(tracks allowed)
			(vias allowed)
			(pads allowed)
			(copperpour allowed)
			(footprints allowed)
		)
		(placement
			(enabled no)
			(sheetname "")
		)
		(fill
			(thermal_gap 0.5)
			(thermal_bridge_width 0.5)
			(island_removal_mode 0)
		)
		(polygon
			(pts
				(xy 180.423058 -208.90484) (xy 180.423058 -208.67624) (xy 182.455058 -208.67624) (xy 182.455058 -208.90484)
			)
		)
	)
	(zone
		(layer "F.Cu")
		(hatch none 0.5)
		(connect_pads
			(clearance 0)
		)
		(min_thickness 0.25)
		(keepout
			(tracks allowed)
			(vias allowed)
			(pads allowed)
			(copperpour allowed)
			(footprints allowed)
		)
		(placement
			(enabled no)
			(sheetname "")
		)
		(fill
			(thermal_gap 0.5)
			(thermal_bridge_width 0.5)
			(island_removal_mode 0)
		)
		(polygon
			(pts
				(xy 307.76291 -226.86645) (xy 307.76291 -226.422712) (xy 310.088026 -226.422712) (xy 310.088026 -226.86645)
			)
		)
	)
	(zone
		(layer "F.Cu")
		(hatch none 0.5)
		(connect_pads
			(clearance 0)
		)
		(min_thickness 0.25)
		(keepout
			(tracks allowed)
			(vias allowed)
			(pads allowed)
			(copperpour allowed)
			(footprints allowed)
		)
		(placement
			(enabled no)
			(sheetname "")
		)
		(fill
			(thermal_gap 0.5)
			(thermal_bridge_width 0.5)
			(island_removal_mode 0)
		)
		(polygon
			(pts
				(xy 262.50011 -277.016464) (xy 262.50011 -276.572726) (xy 264.825226 -276.572726) (xy 264.825226 -277.016464)
			)
		)
	)
	(zone
		(layer "F.Cu")
		(hatch none 0.5)
		(connect_pads
			(clearance 0)
		)
		(min_thickness 0.25)
		(keepout
			(tracks allowed)
			(vias allowed)
			(pads allowed)
			(copperpour allowed)
			(footprints allowed)
		)
		(placement
			(enabled no)
			(sheetname "")
		)
		(fill
			(thermal_gap 0.5)
			(thermal_bridge_width 0.5)
			(island_removal_mode 0)
		)
		(polygon
			(pts
				(xy 41.140888 -319.243456) (xy 41.140888 -316.881256) (xy 43.757088 -316.881256) (xy 43.757088 -319.243456)
			)
		)
	)
	(zone
		(layer "F.Cu")
		(hatch none 0.5)
		(connect_pads
			(clearance 0)
		)
		(min_thickness 0.25)
		(keepout
			(tracks allowed)
			(vias allowed)
			(pads allowed)
			(copperpour allowed)
			(footprints allowed)
		)
		(placement
			(enabled no)
			(sheetname "")
		)
		(fill
			(thermal_gap 0.5)
			(thermal_bridge_width 0.5)
			(island_removal_mode 0)
		)
		(polygon
			(pts
				(xy 424.919394 -251.176282) (xy 426.951394 -251.176282) (xy 426.951394 -251.404882) (xy 424.919394 -251.404882)
				(xy 424.75277 -251.404882) (xy 424.75277 -251.176282)
			)
		)
	)
	(zone
		(layer "F.Cu")
		(hatch none 0.5)
		(connect_pads
			(clearance 0)
		)
		(min_thickness 0.25)
		(keepout
			(tracks allowed)
			(vias allowed)
			(pads allowed)
			(copperpour allowed)
			(footprints allowed)
		)
		(placement
			(enabled no)
			(sheetname "")
		)
		(fill
			(thermal_gap 0.5)
			(thermal_bridge_width 0.5)
			(island_removal_mode 0)
		)
		(polygon
			(pts
				(xy 56.37911 -282.11653) (xy 56.37911 -281.672792) (xy 58.704226 -281.672792) (xy 58.704226 -282.11653)
			)
		)
	)
	(zone
		(layer "F.Cu")
		(hatch none 0.5)
		(connect_pads
			(clearance 0)
		)
		(min_thickness 0.25)
		(keepout
			(tracks allowed)
			(vias allowed)
			(pads allowed)
			(copperpour allowed)
			(footprints allowed)
		)
		(placement
			(enabled no)
			(sheetname "")
		)
		(fill
			(thermal_gap 0.5)
			(thermal_bridge_width 0.5)
			(island_removal_mode 0)
		)
		(polygon
			(pts
				(xy 176.979326 -281.776424) (xy 179.011326 -281.776424) (xy 179.011326 -282.005024) (xy 176.979326 -282.005024)
				(xy 176.843182 -282.005024) (xy 176.796192 -282.005024) (xy 176.796192 -281.776424) (xy 176.843182 -281.776424)
			)
		)
	)
	(zone
		(layer "F.Cu")
		(hatch none 0.5)
		(connect_pads
			(clearance 0)
		)
		(min_thickness 0.25)
		(keepout
			(tracks allowed)
			(vias allowed)
			(pads allowed)
			(copperpour allowed)
			(footprints allowed)
		)
		(placement
			(enabled no)
			(sheetname "")
		)
		(fill
			(thermal_gap 0.5)
			(thermal_bridge_width 0.5)
			(island_removal_mode 0)
		)
		(polygon
			(pts
				(xy 64.002412 -313.566556) (xy 64.002412 -313.122818) (xy 66.161412 -313.122818) (xy 66.161412 -313.566556)
			)
		)
	)
	(zone
		(layer "F.Cu")
		(hatch none 0.5)
		(connect_pads
			(clearance 0)
		)
		(min_thickness 0.25)
		(keepout
			(tracks allowed)
			(vias allowed)
			(pads allowed)
			(copperpour allowed)
			(footprints not_allowed)
		)
		(placement
			(enabled no)
			(sheetname "")
		)
		(fill
			(thermal_gap 0.5)
			(thermal_bridge_width 0.5)
			(island_removal_mode 0)
		)
		(polygon
			(pts
				(arc
					(start 290.74999 -435.600094)
					(mid 293.550086 -432.799998)
					(end 296.349928 -435.600094)
				)
				(arc
					(start 296.349928 -435.600094)
					(mid 293.550086 -438.399936)
					(end 290.74999 -435.600094)
				)
			)
		)
	)
	(zone
		(layer "F.Cu")
		(hatch none 0.5)
		(connect_pads
			(clearance 0)
		)
		(min_thickness 0.25)
		(keepout
			(tracks allowed)
			(vias allowed)
			(pads allowed)
			(copperpour allowed)
			(footprints allowed)
		)
		(placement
			(enabled no)
			(sheetname "")
		)
		(fill
			(thermal_gap 0.5)
			(thermal_bridge_width 0.5)
			(island_removal_mode 0)
		)
		(polygon
			(pts
				(xy 165.335458 -283.704792) (xy 165.335458 -283.476192) (xy 167.367458 -283.476192) (xy 167.367458 -283.704792)
			)
		)
	)
	(zone
		(layer "F.Cu")
		(hatch none 0.5)
		(connect_pads
			(clearance 0)
		)
		(min_thickness 0.25)
		(keepout
			(tracks allowed)
			(vias allowed)
			(pads allowed)
			(copperpour allowed)
			(footprints not_allowed)
		)
		(placement
			(enabled no)
			(sheetname "")
		)
		(fill
			(thermal_gap 0.5)
			(thermal_bridge_width 0.5)
			(island_removal_mode 0)
		)
		(polygon
			(pts
				(xy 399.869914 -311.770014) (xy 399.869914 -191.77) (xy 319.870074 -191.77) (xy 319.870074 -311.770014)
				(xy 359.819956 -311.770014) (xy 359.819956 -296.720006) (xy 350.164908 -296.720006) (xy 350.164908 -293.269924)
				(xy 369.57508 -293.269924) (xy 369.57508 -296.720006) (xy 359.920032 -296.720006) (xy 359.920032 -311.770014)
			)
		)
	)
	(zone
		(layer "F.Cu")
		(hatch none 0.5)
		(connect_pads
			(clearance 0)
		)
		(min_thickness 0.25)
		(keepout
			(tracks allowed)
			(vias allowed)
			(pads allowed)
			(copperpour allowed)
			(footprints allowed)
		)
		(placement
			(enabled no)
			(sheetname "")
		)
		(fill
			(thermal_gap 0.5)
			(thermal_bridge_width 0.5)
			(island_removal_mode 0)
		)
		(polygon
			(pts
				(xy 440.006994 -205.27645) (xy 442.038994 -205.27645) (xy 442.038994 -205.50505) (xy 440.006994 -205.50505)
				(xy 439.87085 -205.50505) (xy 439.82386 -205.50505) (xy 439.82386 -205.27645) (xy 439.87085 -205.27645)
			)
		)
	)
	(zone
		(layer "F.Cu")
		(hatch none 0.5)
		(connect_pads
			(clearance 0)
		)
		(min_thickness 0.25)
		(keepout
			(tracks not_allowed)
			(vias allowed)
			(pads allowed)
			(copperpour not_allowed)
			(footprints allowed)
		)
		(placement
			(enabled no)
			(sheetname "")
		)
		(fill
			(thermal_gap 0.5)
			(thermal_bridge_width 0.5)
			(island_removal_mode 0)
		)
		(polygon
			(pts
				(arc
					(start 333.854806 -353.525074)
					(mid 329.854814 -357.525066)
					(end 325.854822 -353.525074)
				)
				(arc
					(start 325.854822 -353.525074)
					(mid 329.854814 -349.525082)
					(end 333.854806 -353.525074)
				)
			)
		)
	)
	(zone
		(layer "F.Cu")
		(hatch none 0.5)
		(connect_pads
			(clearance 0)
		)
		(min_thickness 0.25)
		(keepout
			(tracks allowed)
			(vias allowed)
			(pads allowed)
			(copperpour allowed)
			(footprints allowed)
		)
		(placement
			(enabled no)
			(sheetname "")
		)
		(fill
			(thermal_gap 0.5)
			(thermal_bridge_width 0.5)
			(island_removal_mode 0)
		)
		(polygon
			(pts
				(xy 26.20391 -269.366492) (xy 26.20391 -268.922754) (xy 28.529026 -268.922754) (xy 28.529026 -269.366492)
			)
		)
	)
	(zone
		(layer "F.Cu")
		(hatch none 0.5)
		(connect_pads
			(clearance 0)
		)
		(min_thickness 0.25)
		(keepout
			(tracks allowed)
			(vias allowed)
			(pads allowed)
			(copperpour allowed)
			(footprints allowed)
		)
		(placement
			(enabled no)
			(sheetname "")
		)
		(fill
			(thermal_gap 0.5)
			(thermal_bridge_width 0.5)
			(island_removal_mode 0)
		)
		(polygon
			(pts
				(xy 274.143978 -304.216562) (xy 274.143978 -303.772824) (xy 276.469094 -303.772824) (xy 276.469094 -304.216562)
			)
		)
	)
	(zone
		(layer "F.Cu")
		(hatch none 0.5)
		(connect_pads
			(clearance 0)
		)
		(min_thickness 0.25)
		(keepout
			(tracks allowed)
			(vias allowed)
			(pads allowed)
			(copperpour allowed)
			(footprints not_allowed)
		)
		(placement
			(enabled no)
			(sheetname "")
		)
		(fill
			(thermal_gap 0.5)
			(thermal_bridge_width 0.5)
			(island_removal_mode 0)
		)
		(polygon
			(pts
				(arc
					(start 356.125018 -431.360072)
					(mid 359.774998 -427.710092)
					(end 363.424978 -431.360072)
				)
				(arc
					(start 363.424978 -431.360072)
					(mid 359.774998 -435.010052)
					(end 356.125018 -431.360072)
				)
			)
		)
	)
	(zone
		(layer "F.Cu")
		(hatch none 0.5)
		(connect_pads
			(clearance 0)
		)
		(min_thickness 0.25)
		(keepout
			(tracks allowed)
			(vias allowed)
			(pads allowed)
			(copperpour allowed)
			(footprints allowed)
		)
		(placement
			(enabled no)
			(sheetname "")
		)
		(fill
			(thermal_gap 0.5)
			(thermal_bridge_width 0.5)
			(island_removal_mode 0)
		)
		(polygon
			(pts
				(xy 148.613368 -410.948886) (xy 148.613368 -406.105868) (xy 150.497794 -406.105868) (xy 150.497794 -410.948886)
			)
		)
	)
	(zone
		(layer "F.Cu")
		(hatch none 0.5)
		(connect_pads
			(clearance 0)
		)
		(min_thickness 0.25)
		(keepout
			(tracks not_allowed)
			(vias allowed)
			(pads allowed)
			(copperpour not_allowed)
			(footprints allowed)
		)
		(placement
			(enabled no)
			(sheetname "")
		)
		(fill
			(thermal_gap 0.5)
			(thermal_bridge_width 0.5)
			(island_removal_mode 0)
		)
		(polygon
			(pts
				(arc
					(start 328.254614 -353.525074)
					(mid 329.854814 -351.924874)
					(end 331.45476 -353.525074)
				)
				(arc
					(start 331.45476 -353.525074)
					(mid 329.854814 -355.12502)
					(end 328.254614 -353.525074)
				)
			)
		)
	)
	(zone
		(layer "F.Cu")
		(hatch none 0.5)
		(connect_pads
			(clearance 0)
		)
		(min_thickness 0.25)
		(keepout
			(tracks allowed)
			(vias allowed)
			(pads allowed)
			(copperpour allowed)
			(footprints allowed)
		)
		(placement
			(enabled no)
			(sheetname "")
		)
		(fill
			(thermal_gap 0.5)
			(thermal_bridge_width 0.5)
			(island_removal_mode 0)
		)
		(polygon
			(pts
				(xy 428.363126 -273.504914) (xy 428.363126 -273.276314) (xy 430.395126 -273.276314) (xy 430.395126 -273.504914)
			)
		)
	)
	(zone
		(layer "F.Cu")
		(hatch none 0.5)
		(connect_pads
			(clearance 0)
		)
		(min_thickness 0.25)
		(keepout
			(tracks allowed)
			(vias allowed)
			(pads allowed)
			(copperpour allowed)
			(footprints allowed)
		)
		(placement
			(enabled no)
			(sheetname "")
		)
		(fill
			(thermal_gap 0.5)
			(thermal_bridge_width 0.5)
			(island_removal_mode 0)
		)
		(polygon
			(pts
				(xy 428.363126 -308.354984) (xy 428.363126 -308.126384) (xy 430.395126 -308.126384) (xy 430.395126 -308.354984)
			)
		)
	)
	(zone
		(layer "F.Cu")
		(hatch none 0.5)
		(connect_pads
			(clearance 0)
		)
		(min_thickness 0.25)
		(keepout
			(tracks allowed)
			(vias allowed)
			(pads allowed)
			(copperpour allowed)
			(footprints allowed)
		)
		(placement
			(enabled no)
			(sheetname "")
		)
		(fill
			(thermal_gap 0.5)
			(thermal_bridge_width 0.5)
			(island_removal_mode 0)
		)
		(polygon
			(pts
				(xy 180.423058 -231.85501) (xy 180.423058 -231.62641) (xy 182.455058 -231.62641) (xy 182.455058 -231.85501)
			)
		)
	)
	(zone
		(layer "F.Cu")
		(hatch none 0.5)
		(connect_pads
			(clearance 0)
		)
		(min_thickness 0.25)
		(keepout
			(tracks allowed)
			(vias allowed)
			(pads allowed)
			(copperpour allowed)
			(footprints not_allowed)
		)
		(placement
			(enabled no)
			(sheetname "")
		)
		(fill
			(thermal_gap 0.5)
			(thermal_bridge_width 0.5)
			(island_removal_mode 0)
		)
		(polygon
			(pts
				(arc
					(start 467.300056 -353.167696)
					(mid 453.460093 -347.700092)
					(end 467.300056 -342.232488)
				)
			)
		)
	)
	(zone
		(layer "F.Cu")
		(hatch none 0.5)
		(connect_pads
			(clearance 0)
		)
		(min_thickness 0.25)
		(keepout
			(tracks allowed)
			(vias allowed)
			(pads allowed)
			(copperpour allowed)
			(footprints not_allowed)
		)
		(placement
			(enabled no)
			(sheetname "")
		)
		(fill
			(thermal_gap 0.5)
			(thermal_bridge_width 0.5)
			(island_removal_mode 0)
		)
		(polygon
			(pts
				(arc
					(start 89.899998 -22.29993)
					(mid 94.899988 -17.29994)
					(end 99.899978 -22.29993)
				)
				(arc
					(start 99.899978 -22.29993)
					(mid 94.899988 -27.29992)
					(end 89.899998 -22.29993)
				)
			)
		)
	)
	(zone
		(layer "F.Cu")
		(hatch none 0.5)
		(connect_pads
			(clearance 0)
		)
		(min_thickness 0.25)
		(keepout
			(tracks allowed)
			(vias allowed)
			(pads allowed)
			(copperpour allowed)
			(footprints allowed)
		)
		(placement
			(enabled no)
			(sheetname "")
		)
		(fill
			(thermal_gap 0.5)
			(thermal_bridge_width 0.5)
			(island_removal_mode 0)
		)
		(polygon
			(pts
				(xy 63.951612 -294.01643) (xy 63.951612 -293.572692) (xy 66.237612 -293.572692) (xy 66.237612 -294.01643)
			)
		)
	)
	(zone
		(layer "F.Cu")
		(hatch none 0.5)
		(connect_pads
			(clearance 0)
		)
		(min_thickness 0.25)
		(keepout
			(tracks allowed)
			(vias allowed)
			(pads allowed)
			(copperpour allowed)
			(footprints allowed)
		)
		(placement
			(enabled no)
			(sheetname "")
		)
		(fill
			(thermal_gap 0.5)
			(thermal_bridge_width 0.5)
			(island_removal_mode 0)
		)
		(polygon
			(pts
				(xy 180.423058 -199.554846) (xy 180.423058 -199.326246) (xy 182.455058 -199.326246) (xy 182.455058 -199.554846)
			)
		)
	)
	(zone
		(layer "F.Cu")
		(hatch none 0.5)
		(connect_pads
			(clearance 0)
		)
		(min_thickness 0.25)
		(keepout
			(tracks allowed)
			(vias allowed)
			(pads allowed)
			(copperpour allowed)
			(footprints allowed)
		)
		(placement
			(enabled no)
			(sheetname "")
		)
		(fill
			(thermal_gap 0.5)
			(thermal_bridge_width 0.5)
			(island_removal_mode 0)
		)
		(polygon
			(pts
				(xy 413.275526 -289.654996) (xy 413.275526 -289.426396) (xy 415.307526 -289.426396) (xy 415.307526 -289.654996)
			)
		)
	)
	(zone
		(layer "F.Cu")
		(hatch none 0.5)
		(connect_pads
			(clearance 0)
		)
		(min_thickness 0.25)
		(keepout
			(tracks allowed)
			(vias allowed)
			(pads allowed)
			(copperpour allowed)
			(footprints allowed)
		)
		(placement
			(enabled no)
			(sheetname "")
		)
		(fill
			(thermal_gap 0.5)
			(thermal_bridge_width 0.5)
			(island_removal_mode 0)
		)
		(polygon
			(pts
				(xy 311.91708 -296.56659) (xy 311.91708 -296.122852) (xy 314.12688 -296.122852) (xy 314.12688 -296.56659)
			)
		)
	)
	(zone
		(layer "F.Cu")
		(hatch none 0.5)
		(connect_pads
			(clearance 0)
		)
		(min_thickness 0.25)
		(keepout
			(tracks allowed)
			(vias allowed)
			(pads allowed)
			(copperpour allowed)
			(footprints allowed)
		)
		(placement
			(enabled no)
			(sheetname "")
		)
		(fill
			(thermal_gap 0.5)
			(thermal_bridge_width 0.5)
			(island_removal_mode 0)
		)
		(polygon
			(pts
				(xy 289.231578 -265.966448) (xy 289.231578 -265.52271) (xy 291.556694 -265.52271) (xy 291.556694 -265.966448)
			)
		)
	)
	(zone
		(layer "F.Cu")
		(hatch none 0.5)
		(connect_pads
			(clearance 0)
		)
		(min_thickness 0.25)
		(keepout
			(tracks allowed)
			(vias allowed)
			(pads allowed)
			(copperpour allowed)
			(footprints allowed)
		)
		(placement
			(enabled no)
			(sheetname "")
		)
		(fill
			(thermal_gap 0.5)
			(thermal_bridge_width 0.5)
			(island_removal_mode 0)
		)
		(polygon
			(pts
				(xy 58.704226 -238.766604) (xy 56.37911 -238.766604) (xy 56.032146 -238.766604) (xy 56.032146 -237.572042)
				(xy 58.967878 -237.572042) (xy 58.967878 -238.766604)
			)
		)
	)
	(zone
		(layer "F.Cu")
		(hatch none 0.5)
		(connect_pads
			(clearance 0)
		)
		(min_thickness 0.25)
		(keepout
			(tracks allowed)
			(vias allowed)
			(pads allowed)
			(copperpour allowed)
			(footprints allowed)
		)
		(placement
			(enabled no)
			(sheetname "")
		)
		(fill
			(thermal_gap 0.5)
			(thermal_bridge_width 0.5)
			(island_removal_mode 0)
		)
		(polygon
			(pts
				(xy 458.538326 -287.954974) (xy 458.538326 -287.726374) (xy 460.570326 -287.726374) (xy 460.570326 -287.954974)
			)
		)
	)
	(zone
		(layer "F.Cu")
		(hatch none 0.5)
		(connect_pads
			(clearance 0)
		)
		(min_thickness 0.25)
		(keepout
			(tracks not_allowed)
			(vias allowed)
			(pads allowed)
			(copperpour not_allowed)
			(footprints allowed)
		)
		(placement
			(enabled no)
			(sheetname "")
		)
		(fill
			(thermal_gap 0.5)
			(thermal_bridge_width 0.5)
			(island_removal_mode 0)
		)
		(polygon
			(pts
				(xy 417.716462 -172.623988) (xy 416.603942 -172.623988) (xy 416.603942 -172.866304) (xy 417.716462 -172.866304)
			)
		)
	)
	(zone
		(layer "F.Cu")
		(hatch none 0.5)
		(connect_pads
			(clearance 0)
		)
		(min_thickness 0.25)
		(keepout
			(tracks allowed)
			(vias allowed)
			(pads allowed)
			(copperpour allowed)
			(footprints allowed)
		)
		(placement
			(enabled no)
			(sheetname "")
		)
		(fill
			(thermal_gap 0.5)
			(thermal_bridge_width 0.5)
			(island_removal_mode 0)
		)
		(polygon
			(pts
				(xy 210.598258 -282.005024) (xy 210.598258 -281.776424) (xy 212.630258 -281.776424) (xy 212.630258 -282.005024)
			)
		)
	)
	(zone
		(layer "F.Cu")
		(hatch none 0.5)
		(connect_pads
			(clearance 0)
		)
		(min_thickness 0.25)
		(keepout
			(tracks allowed)
			(vias not_allowed)
			(pads allowed)
			(copperpour not_allowed)
			(footprints allowed)
		)
		(placement
			(enabled no)
			(sheetname "")
		)
		(fill
			(thermal_gap 0.5)
			(thermal_bridge_width 0.5)
			(island_removal_mode 0)
		)
		(polygon
			(pts
				(xy 27.369262 -150.787608) (xy 29.756862 -150.787608) (xy 29.756862 -151.605234) (xy 27.369262 -151.605234)
			)
		)
	)
	(zone
		(layer "F.Cu")
		(hatch none 0.5)
		(connect_pads
			(clearance 0)
		)
		(min_thickness 0.25)
		(keepout
			(tracks allowed)
			(vias allowed)
			(pads allowed)
			(copperpour allowed)
			(footprints allowed)
		)
		(placement
			(enabled no)
			(sheetname "")
		)
		(fill
			(thermal_gap 0.5)
			(thermal_bridge_width 0.5)
			(island_removal_mode 0)
		)
		(polygon
			(pts
				(xy 458.538326 -301.554896) (xy 458.538326 -301.326296) (xy 460.570326 -301.326296) (xy 460.570326 -301.554896)
			)
		)
	)
	(zone
		(layer "F.Cu")
		(hatch none 0.5)
		(connect_pads
			(clearance 0)
		)
		(min_thickness 0.25)
		(keepout
			(tracks not_allowed)
			(vias allowed)
			(pads allowed)
			(copperpour not_allowed)
			(footprints allowed)
		)
		(placement
			(enabled no)
			(sheetname "")
		)
		(fill
			(thermal_gap 0.5)
			(thermal_bridge_width 0.5)
			(island_removal_mode 0)
		)
		(polygon
			(pts
				(arc
					(start 172.899832 -160.50006)
					(mid 167.899842 -165.50005)
					(end 162.899852 -160.50006)
				)
				(arc
					(start 162.899852 -160.50006)
					(mid 167.899842 -155.50007)
					(end 172.899832 -160.50006)
				)
			)
		)
	)
	(zone
		(layer "F.Cu")
		(hatch none 0.5)
		(connect_pads
			(clearance 0)
		)
		(min_thickness 0.25)
		(keepout
			(tracks allowed)
			(vias allowed)
			(pads allowed)
			(copperpour allowed)
			(footprints allowed)
		)
		(placement
			(enabled no)
			(sheetname "")
		)
		(fill
			(thermal_gap 0.5)
			(thermal_bridge_width 0.5)
			(island_removal_mode 0)
		)
		(polygon
			(pts
				(xy 59.822842 -197.966584) (xy 59.822842 -197.522846) (xy 62.147958 -197.522846) (xy 62.147958 -197.966584)
			)
		)
	)
	(zone
		(layer "F.Cu")
		(hatch none 0.5)
		(connect_pads
			(clearance 0)
		)
		(min_thickness 0.25)
		(keepout
			(tracks not_allowed)
			(vias allowed)
			(pads allowed)
			(copperpour not_allowed)
			(footprints allowed)
		)
		(placement
			(enabled no)
			(sheetname "")
		)
		(fill
			(thermal_gap 0.5)
			(thermal_bridge_width 0.5)
			(island_removal_mode 0)
		)
		(polygon
			(pts
				(arc
					(start 176.950116 -435.600094)
					(mid 179.750212 -432.799998)
					(end 182.550054 -435.600094)
				)
				(arc
					(start 182.550054 -435.600094)
					(mid 179.750212 -438.399936)
					(end 176.950116 -435.600094)
				)
			)
		)
	)
	(zone
		(layer "F.Cu")
		(hatch none 0.5)
		(connect_pads
			(clearance 0)
		)
		(min_thickness 0.25)
		(keepout
			(tracks allowed)
			(vias allowed)
			(pads allowed)
			(copperpour allowed)
			(footprints allowed)
		)
		(placement
			(enabled no)
			(sheetname "")
		)
		(fill
			(thermal_gap 0.5)
			(thermal_bridge_width 0.5)
			(island_removal_mode 0)
		)
		(polygon
			(pts
				(xy 26.20391 -288.06648) (xy 26.20391 -287.622742) (xy 28.529026 -287.622742) (xy 28.529026 -288.06648)
			)
		)
	)
	(zone
		(layer "F.Cu")
		(hatch none 0.5)
		(connect_pads
			(clearance 0)
		)
		(min_thickness 0.25)
		(keepout
			(tracks allowed)
			(vias allowed)
			(pads allowed)
			(copperpour allowed)
			(footprints allowed)
		)
		(placement
			(enabled no)
			(sheetname "")
		)
		(fill
			(thermal_gap 0.5)
			(thermal_bridge_width 0.5)
			(island_removal_mode 0)
		)
		(polygon
			(pts
				(xy 304.319178 -234.922822) (xy 306.644294 -234.922822) (xy 306.923948 -234.922822) (xy 306.923948 -235.864908)
				(xy 303.984406 -235.864908) (xy 303.984406 -234.922822)
			)
		)
	)
	(zone
		(layer "F.Cu")
		(hatch none 0.5)
		(connect_pads
			(clearance 0)
		)
		(min_thickness 0.25)
		(keepout
			(tracks allowed)
			(vias allowed)
			(pads allowed)
			(copperpour allowed)
			(footprints allowed)
		)
		(placement
			(enabled no)
			(sheetname "")
		)
		(fill
			(thermal_gap 0.5)
			(thermal_bridge_width 0.5)
			(island_removal_mode 0)
		)
		(polygon
			(pts
				(xy 289.231578 -247.26646) (xy 289.231578 -246.822722) (xy 291.556694 -246.822722) (xy 291.556694 -247.26646)
			)
		)
	)
	(zone
		(layer "F.Cu")
		(hatch none 0.5)
		(connect_pads
			(clearance 0)
		)
		(min_thickness 0.25)
		(keepout
			(tracks allowed)
			(vias allowed)
			(pads allowed)
			(copperpour allowed)
			(footprints allowed)
		)
		(placement
			(enabled no)
			(sheetname "")
		)
		(fill
			(thermal_gap 0.5)
			(thermal_bridge_width 0.5)
			(island_removal_mode 0)
		)
		(polygon
			(pts
				(xy 292.67531 -311.01665) (xy 292.67531 -310.572912) (xy 295.000426 -310.572912) (xy 295.000426 -311.01665)
			)
		)
	)
	(zone
		(layer "F.Cu")
		(hatch none 0.5)
		(connect_pads
			(clearance 0)
		)
		(min_thickness 0.25)
		(keepout
			(tracks allowed)
			(vias allowed)
			(pads allowed)
			(copperpour allowed)
			(footprints allowed)
		)
		(placement
			(enabled no)
			(sheetname "")
		)
		(fill
			(thermal_gap 0.5)
			(thermal_bridge_width 0.5)
			(island_removal_mode 0)
		)
		(polygon
			(pts
				(xy 29.647642 -252.366526) (xy 29.647642 -251.922788) (xy 31.972758 -251.922788) (xy 31.972758 -252.366526)
			)
		)
	)
	(zone
		(layer "F.Cu")
		(hatch none 0.5)
		(connect_pads
			(clearance 0)
		)
		(min_thickness 0.25)
		(keepout
			(tracks allowed)
			(vias allowed)
			(pads allowed)
			(copperpour allowed)
			(footprints allowed)
		)
		(placement
			(enabled no)
			(sheetname "")
		)
		(fill
			(thermal_gap 0.5)
			(thermal_bridge_width 0.5)
			(island_removal_mode 0)
		)
		(polygon
			(pts
				(xy 41.29151 -220.9165) (xy 41.29151 -220.472762) (xy 43.616626 -220.472762) (xy 43.616626 -220.9165)
			)
		)
	)
	(zone
		(layer "F.Cu")
		(hatch none 0.5)
		(connect_pads
			(clearance 0)
		)
		(min_thickness 0.25)
		(keepout
			(tracks allowed)
			(vias allowed)
			(pads allowed)
			(copperpour allowed)
			(footprints allowed)
		)
		(placement
			(enabled no)
			(sheetname "")
		)
		(fill
			(thermal_gap 0.5)
			(thermal_bridge_width 0.5)
			(island_removal_mode 0)
		)
		(polygon
			(pts
				(xy 259.056378 -200.51649) (xy 259.056378 -200.072752) (xy 261.381494 -200.072752) (xy 261.381494 -200.51649)
			)
		)
	)
	(zone
		(layer "F.Cu")
		(hatch none 0.5)
		(connect_pads
			(clearance 0)
		)
		(min_thickness 0.25)
		(keepout
			(tracks allowed)
			(vias allowed)
			(pads allowed)
			(copperpour allowed)
			(footprints allowed)
		)
		(placement
			(enabled no)
			(sheetname "")
		)
		(fill
			(thermal_gap 0.5)
			(thermal_bridge_width 0.5)
			(island_removal_mode 0)
		)
		(polygon
			(pts
				(xy 192.066926 -278.37638) (xy 194.098926 -278.37638) (xy 194.098926 -278.378666) (xy 194.277742 -278.378666)
				(xy 194.277742 -278.615902) (xy 194.415664 -278.615902) (xy 194.458844 -278.659082) (xy 194.458844 -278.791924)
				(xy 194.458844 -279.095962) (xy 194.3862 -279.168606) (xy 191.845946 -279.168606) (xy 191.704722 -279.027382)
				(xy 191.704722 -278.830278) (xy 191.786256 -278.748744) (xy 191.786256 -278.37638) (xy 191.883792 -278.37638)
				(xy 191.930782 -278.37638)
			)
		)
	)
	(zone
		(layer "F.Cu")
		(hatch none 0.5)
		(connect_pads
			(clearance 0)
		)
		(min_thickness 0.25)
		(keepout
			(tracks allowed)
			(vias allowed)
			(pads allowed)
			(copperpour allowed)
			(footprints allowed)
		)
		(placement
			(enabled no)
			(sheetname "")
		)
		(fill
			(thermal_gap 0.5)
			(thermal_bridge_width 0.5)
			(island_removal_mode 0)
		)
		(polygon
			(pts
				(xy 337.54568 -359.639108) (xy 337.54568 -357.391208) (xy 342.47836 -357.391208) (xy 342.47836 -359.639108)
			)
		)
	)
	(zone
		(layer "F.Cu")
		(hatch none 0.5)
		(connect_pads
			(clearance 0)
		)
		(min_thickness 0.25)
		(keepout
			(tracks allowed)
			(vias allowed)
			(pads allowed)
			(copperpour allowed)
			(footprints allowed)
		)
		(placement
			(enabled no)
			(sheetname "")
		)
		(fill
			(thermal_gap 0.5)
			(thermal_bridge_width 0.5)
			(island_removal_mode 0)
		)
		(polygon
			(pts
				(xy 304.319178 -233.2228) (xy 306.644294 -233.2228) (xy 306.708302 -233.2228) (xy 306.708302 -234.137962)
				(xy 304.185574 -234.137962) (xy 304.185574 -233.2228)
			)
		)
	)
	(zone
		(layer "F.Cu")
		(hatch none 0.5)
		(connect_pads
			(clearance 0)
		)
		(min_thickness 0.25)
		(keepout
			(tracks allowed)
			(vias allowed)
			(pads allowed)
			(copperpour allowed)
			(footprints allowed)
		)
		(placement
			(enabled no)
			(sheetname "")
		)
		(fill
			(thermal_gap 0.5)
			(thermal_bridge_width 0.5)
			(island_removal_mode 0)
		)
		(polygon
			(pts
				(xy 29.647642 -218.366594) (xy 29.647642 -217.922856) (xy 31.972758 -217.922856) (xy 31.972758 -218.366594)
			)
		)
	)
	(zone
		(layer "F.Cu")
		(hatch none 0.5)
		(connect_pads
			(clearance 0)
		)
		(min_thickness 0.25)
		(keepout
			(tracks allowed)
			(vias allowed)
			(pads allowed)
			(copperpour allowed)
			(footprints allowed)
		)
		(placement
			(enabled no)
			(sheetname "")
		)
		(fill
			(thermal_gap 0.5)
			(thermal_bridge_width 0.5)
			(island_removal_mode 0)
		)
		(polygon
			(pts
				(xy 210.598258 -302.405034) (xy 210.598258 -302.176434) (xy 212.630258 -302.176434) (xy 212.630258 -302.405034)
			)
		)
	)
	(zone
		(layer "F.Cu")
		(hatch none 0.5)
		(connect_pads
			(clearance 0)
		)
		(min_thickness 0.25)
		(keepout
			(tracks allowed)
			(vias allowed)
			(pads allowed)
			(copperpour allowed)
			(footprints allowed)
		)
		(placement
			(enabled no)
			(sheetname "")
		)
		(fill
			(thermal_gap 0.5)
			(thermal_bridge_width 0.5)
			(island_removal_mode 0)
		)
		(polygon
			(pts
				(xy 157.797754 -240.126266) (xy 159.829754 -240.126266) (xy 159.970216 -240.126266) (xy 159.970216 -240.838736)
				(xy 157.582108 -240.838736) (xy 157.582108 -240.126266)
			)
		)
	)
	(zone
		(layer "F.Cu")
		(hatch none 0.5)
		(connect_pads
			(clearance 0)
		)
		(min_thickness 0.25)
		(keepout
			(tracks allowed)
			(vias allowed)
			(pads allowed)
			(copperpour allowed)
			(footprints allowed)
		)
		(placement
			(enabled no)
			(sheetname "")
		)
		(fill
			(thermal_gap 0.5)
			(thermal_bridge_width 0.5)
			(island_removal_mode 0)
		)
		(polygon
			(pts
				(xy 274.143978 -200.51649) (xy 274.143978 -200.072752) (xy 276.469094 -200.072752) (xy 276.469094 -200.51649)
			)
		)
	)
	(zone
		(layer "F.Cu")
		(hatch none 0.5)
		(connect_pads
			(clearance 0)
		)
		(min_thickness 0.25)
		(keepout
			(tracks allowed)
			(vias allowed)
			(pads allowed)
			(copperpour allowed)
			(footprints allowed)
		)
		(placement
			(enabled no)
			(sheetname "")
		)
		(fill
			(thermal_gap 0.5)
			(thermal_bridge_width 0.5)
			(island_removal_mode 0)
		)
		(polygon
			(pts
				(xy 165.366954 -267.554964) (xy 165.366954 -267.326364) (xy 167.367458 -267.326364) (xy 167.367458 -267.554964)
			)
		)
	)
	(zone
		(layer "F.Cu")
		(hatch none 0.5)
		(connect_pads
			(clearance 0)
		)
		(min_thickness 0.25)
		(keepout
			(tracks allowed)
			(vias allowed)
			(pads allowed)
			(copperpour allowed)
			(footprints not_allowed)
		)
		(placement
			(enabled no)
			(sheetname "")
		)
		(fill
			(thermal_gap 0.5)
			(thermal_bridge_width 0.5)
			(island_removal_mode 0)
		)
		(polygon
			(pts
				(xy 158.399988 -440.989974) (xy 161.59988 -440.989974) (xy 161.59988 -417.889944) (xy 121.299986 -417.889944)
				(xy 121.299986 -440.989974) (xy 124.499878 -440.989974) (xy 124.499878 -421.09009) (xy 158.399988 -421.09009)
			)
		)
	)
	(zone
		(layer "F.Cu")
		(hatch none 0.5)
		(connect_pads
			(clearance 0)
		)
		(min_thickness 0.25)
		(keepout
			(tracks allowed)
			(vias allowed)
			(pads allowed)
			(copperpour allowed)
			(footprints allowed)
		)
		(placement
			(enabled no)
			(sheetname "")
		)
		(fill
			(thermal_gap 0.5)
			(thermal_bridge_width 0.5)
			(island_removal_mode 0)
		)
		(polygon
			(pts
				(xy 137.34288 -219.299028) (xy 137.6299 -219.299028) (xy 137.66038 -219.268548) (xy 137.66038 -218.641168)
				(xy 137.57402 -218.554808) (xy 137.38606 -218.554808) (xy 137.3124 -218.628468) (xy 137.3124 -219.268548)
			)
		)
	)
	(zone
		(layer "F.Cu")
		(hatch none 0.5)
		(connect_pads
			(clearance 0)
		)
		(min_thickness 0.25)
		(keepout
			(tracks allowed)
			(vias allowed)
			(pads allowed)
			(copperpour allowed)
			(footprints allowed)
		)
		(placement
			(enabled no)
			(sheetname "")
		)
		(fill
			(thermal_gap 0.5)
			(thermal_bridge_width 0.5)
			(island_removal_mode 0)
		)
		(polygon
			(pts
				(xy 161.891726 -297.304968) (xy 161.891726 -297.076368) (xy 163.923726 -297.076368) (xy 163.923726 -297.304968)
			)
		)
	)
	(zone
		(layer "F.Cu")
		(hatch none 0.5)
		(connect_pads
			(clearance 0)
		)
		(min_thickness 0.25)
		(keepout
			(tracks allowed)
			(vias allowed)
			(pads allowed)
			(copperpour allowed)
			(footprints allowed)
		)
		(placement
			(enabled no)
			(sheetname "")
		)
		(fill
			(thermal_gap 0.5)
			(thermal_bridge_width 0.5)
			(island_removal_mode 0)
		)
		(polygon
			(pts
				(xy 455.094594 -260.754876) (xy 455.094594 -260.526276) (xy 457.126594 -260.526276) (xy 457.126594 -260.754876)
			)
		)
	)
	(zone
		(layer "F.Cu")
		(hatch none 0.5)
		(connect_pads
			(clearance 0)
		)
		(min_thickness 0.25)
		(keepout
			(tracks allowed)
			(vias allowed)
			(pads allowed)
			(copperpour allowed)
			(footprints allowed)
		)
		(placement
			(enabled no)
			(sheetname "")
		)
		(fill
			(thermal_gap 0.5)
			(thermal_bridge_width 0.5)
			(island_removal_mode 0)
		)
		(polygon
			(pts
				(xy 26.20391 -245.566438) (xy 26.20391 -245.1227) (xy 28.529026 -245.1227) (xy 28.529026 -245.566438)
			)
		)
	)
	(zone
		(layer "F.Cu")
		(hatch none 0.5)
		(connect_pads
			(clearance 0)
		)
		(min_thickness 0.25)
		(keepout
			(tracks allowed)
			(vias allowed)
			(pads allowed)
			(copperpour allowed)
			(footprints allowed)
		)
		(placement
			(enabled no)
			(sheetname "")
		)
		(fill
			(thermal_gap 0.5)
			(thermal_bridge_width 0.5)
			(island_removal_mode 0)
		)
		(polygon
			(pts
				(xy 259.056378 -211.566506) (xy 259.056378 -211.122768) (xy 261.381494 -211.122768) (xy 261.381494 -211.566506)
			)
		)
	)
	(zone
		(layer "F.Cu")
		(hatch none 0.5)
		(connect_pads
			(clearance 0)
		)
		(min_thickness 0.25)
		(keepout
			(tracks allowed)
			(vias allowed)
			(pads allowed)
			(copperpour allowed)
			(footprints allowed)
		)
		(placement
			(enabled no)
			(sheetname "")
		)
		(fill
			(thermal_gap 0.5)
			(thermal_bridge_width 0.5)
			(island_removal_mode 0)
		)
		(polygon
			(pts
				(xy 86.17458 -286.586168) (xy 86.4616 -286.586168) (xy 86.49208 -286.555688) (xy 86.49208 -285.928308)
				(xy 86.40572 -285.841948) (xy 86.21776 -285.841948) (xy 86.1441 -285.915608) (xy 86.1441 -286.555688)
			)
		)
	)
	(zone
		(layer "F.Cu")
		(hatch none 0.5)
		(connect_pads
			(clearance 0)
		)
		(min_thickness 0.25)
		(keepout
			(tracks allowed)
			(vias allowed)
			(pads allowed)
			(copperpour allowed)
			(footprints allowed)
		)
		(placement
			(enabled no)
			(sheetname "")
		)
		(fill
			(thermal_gap 0.5)
			(thermal_bridge_width 0.5)
			(island_removal_mode 0)
		)
		(polygon
			(pts
				(xy 297.589702 -361.96778) (xy 295.773602 -361.96778) (xy 295.773602 -360.58856) (xy 297.589702 -360.58856)
			)
		)
	)
	(zone
		(layer "F.Cu")
		(hatch none 0.5)
		(connect_pads
			(clearance 0)
		)
		(min_thickness 0.25)
		(keepout
			(tracks allowed)
			(vias allowed)
			(pads allowed)
			(copperpour allowed)
			(footprints allowed)
		)
		(placement
			(enabled no)
			(sheetname "")
		)
		(fill
			(thermal_gap 0.5)
			(thermal_bridge_width 0.5)
			(island_removal_mode 0)
		)
		(polygon
			(pts
				(xy 219.84716 -404.36546) (xy 219.84716 -401.11426) (xy 223.14662 -401.11426) (xy 223.14662 -404.36546)
			)
		)
	)
	(zone
		(layer "F.Cu")
		(hatch none 0.5)
		(connect_pads
			(clearance 0)
		)
		(min_thickness 0.25)
		(keepout
			(tracks allowed)
			(vias allowed)
			(pads allowed)
			(copperpour allowed)
			(footprints allowed)
		)
		(placement
			(enabled no)
			(sheetname "")
		)
		(fill
			(thermal_gap 0.5)
			(thermal_bridge_width 0.5)
			(island_removal_mode 0)
		)
		(polygon
			(pts
				(xy 83.99145 -237.49254) (xy 83.501484 -237.49254) (xy 83.433666 -237.49254) (xy 83.390994 -237.449868)
				(xy 83.390994 -233.813096) (xy 83.518756 -233.685334) (xy 83.739228 -233.685334) (xy 83.813904 -233.610658)
				(xy 83.813904 -233.052112) (xy 83.800442 -233.03865) (xy 83.653884 -233.03865) (xy 83.446874 -233.03865)
				(xy 83.369404 -232.96118) (xy 83.369404 -231.198166) (xy 83.782408 -230.785162) (xy 83.782408 -229.860856)
				(xy 83.351116 -229.429564) (xy 83.281012 -229.35946) (xy 83.281012 -229.27564) (xy 83.69046 -228.866192)
				(xy 83.964018 -228.866192) (xy 84.056982 -228.773228) (xy 84.056982 -227.904802) (xy 83.85683 -227.70465)
				(xy 83.85683 -222.95612) (xy 83.627722 -222.727012) (xy 83.627722 -222.726758) (xy 83.62823 -222.72625)
				(xy 83.39963 -222.49765) (xy 83.321906 -222.419926) (xy 83.321906 -221.937326) (xy 83.321906 -221.839282)
				(xy 84.124292 -221.036896) (xy 83.196938 -220.109542) (xy 83.115404 -220.028008) (xy 83.115404 -219.932758)
				(xy 83.485228 -219.562934) (xy 83.591654 -219.562934) (xy 83.758786 -219.730066) (xy 83.768692 -219.730066)
				(xy 85.05063 -218.448128) (xy 85.05063 -218.10472) (xy 85.437472 -217.717878) (xy 85.437472 -217.658442)
				(xy 85.413342 -217.634312) (xy 85.413088 -215.81364) (xy 85.557106 -215.669622) (xy 86.155022 -215.669622)
				(xy 86.509352 -215.669622) (xy 87.679784 -214.49919) (xy 87.679784 -214.09152) (xy 87.679784 -213.986618)
				(xy 87.659718 -213.966552) (xy 80.681576 -213.966552) (xy 80.681576 -212.845904) (xy 80.211676 -212.376004)
				(xy 80.106266 -212.376004) (xy 78.538578 -213.943692) (xy 78.538578 -214.049102) (xy 78.538578 -215.236552)
				(xy 78.503018 -215.272112) (xy 76.758038 -217.017092) (xy 76.758038 -217.22842) (xy 76.89723 -217.367612)
				(xy 77.241654 -217.712036) (xy 77.241654 -217.787728) (xy 76.865734 -218.163648) (xy 76.604622 -218.163648)
				(xy 76.537566 -218.230704) (xy 76.313538 -218.454732) (xy 76.313538 -218.550744) (xy 76.049378 -218.814904)
				(xy 75.550522 -219.31376) (xy 75.508358 -219.355924) (xy 75.508358 -219.686632) (xy 75.88123 -220.059504)
				(xy 76.059538 -220.059504) (xy 76.54163 -220.059504) (xy 76.54163 -220.618304) (xy 76.44003 -220.719904)
				(xy 76.450698 -220.730572) (xy 76.450698 -224.053654) (xy 77.042518 -224.645474) (xy 77.042518 -225.221292)
				(xy 76.478638 -225.785172) (xy 76.478638 -226.183952) (xy 76.224638 -226.437952) (xy 76.224638 -226.477322)
				(xy 76.224638 -228.198172) (xy 76.123038 -228.198172) (xy 76.123038 -230.220012) (xy 76.234798 -230.220012)
				(xy 76.234798 -231.692958) (xy 76.31303 -231.692958) (xy 76.82103 -231.692958) (xy 76.821284 -232.097072)
				(xy 77.151738 -232.097072) (xy 77.151738 -232.885234) (xy 77.228192 -232.885234) (xy 77.730858 -232.885234)
				(xy 77.730858 -233.521504) (xy 77.786484 -233.521504) (xy 78.091284 -233.521504) (xy 78.091284 -233.963972)
				(xy 78.360016 -233.963972) (xy 80.292194 -235.895896) (xy 80.292194 -237.097316) (xy 80.367632 -237.172754)
				(xy 80.452214 -237.257336) (xy 80.452214 -238.483648) (xy 80.872838 -238.904272) (xy 80.872838 -240.656618)
				(xy 80.961484 -240.745264) (xy 81.624678 -240.745264) (xy 81.624678 -241.743992) (xy 81.596738 -241.771932)
				(xy 81.596738 -244.486684) (xy 81.589118 -244.494304) (xy 73.892918 -244.494304) (xy 73.674986 -244.276372)
				(xy 73.355708 -244.276372) (xy 73.137776 -244.494304) (xy 73.137776 -244.957092) (xy 72.912478 -245.18239)
				(xy 72.912478 -245.457472) (xy 73.095358 -245.640352) (xy 73.095358 -245.724172) (xy 72.864218 -245.955312)
				(xy 72.864218 -246.08917) (xy 72.864218 -246.620792) (xy 72.630538 -246.854726) (xy 72.589898 -246.895366)
				(xy 72.589898 -247.362472) (xy 73.16216 -247.934734) (xy 73.25233 -247.934734) (xy 73.351898 -247.934734)
				(xy 73.737978 -248.320814) (xy 73.848468 -248.320814) (xy 73.964038 -248.320814) (xy 74.291698 -248.648474)
				(xy 74.448162 -248.648474) (xy 74.479658 -248.648474) (xy 74.756518 -248.925334) (xy 74.877168 -248.925334)
				(xy 75.236578 -248.925334) (xy 75.467718 -249.156474) (xy 75.590908 -249.156474) (xy 75.861418 -249.156474)
				(xy 76.178918 -249.473974) (xy 76.289408 -249.473974) (xy 76.336398 -249.473974) (xy 76.613258 -249.750834)
				(xy 76.693268 -249.750834) (xy 83.811364 -249.75058) (xy 83.811364 -249.325892) (xy 83.767676 -249.282204)
				(xy 83.636612 -249.282204) (xy 83.622642 -249.268234) (xy 83.622642 -248.724674) (xy 83.900264 -248.447052)
				(xy 83.900264 -247.97512) (xy 83.727798 -247.802654) (xy 83.727798 -245.9228) (xy 84.019136 -245.9228)
				(xy 84.019136 -244.758972) (xy 83.72983 -244.758972) (xy 83.72983 -242.105434) (xy 82.738214 -241.113818)
				(xy 82.738214 -239.666018) (xy 83.269582 -239.13465) (xy 83.444588 -239.13465) (xy 83.85683 -238.722408)
				(xy 83.85683 -238.424974) (xy 84.039456 -238.242348) (xy 84.039456 -237.687358) (xy 83.99145 -237.639352)
			)
		)
	)
	(zone
		(layer "F.Cu")
		(hatch none 0.5)
		(connect_pads
			(clearance 0)
		)
		(min_thickness 0.25)
		(keepout
			(tracks allowed)
			(vias allowed)
			(pads allowed)
			(copperpour allowed)
			(footprints allowed)
		)
		(placement
			(enabled no)
			(sheetname "")
		)
		(fill
			(thermal_gap 0.5)
			(thermal_bridge_width 0.5)
			(island_removal_mode 0)
		)
		(polygon
			(pts
				(xy 307.76291 -314.41644) (xy 307.76291 -313.972702) (xy 310.088026 -313.972702) (xy 310.088026 -314.41644)
			)
		)
	)
	(zone
		(layer "F.Cu")
		(hatch none 0.5)
		(connect_pads
			(clearance 0)
		)
		(min_thickness 0.25)
		(keepout
			(tracks allowed)
			(vias allowed)
			(pads allowed)
			(copperpour allowed)
			(footprints allowed)
		)
		(placement
			(enabled no)
			(sheetname "")
		)
		(fill
			(thermal_gap 0.5)
			(thermal_bridge_width 0.5)
			(island_removal_mode 0)
		)
		(polygon
			(pts
				(xy 455.094594 -214.626444) (xy 457.126594 -214.626444) (xy 457.126594 -214.855044) (xy 455.094594 -214.855044)
				(xy 454.95845 -214.855044) (xy 454.91146 -214.855044) (xy 454.91146 -214.626444) (xy 454.95845 -214.626444)
			)
		)
	)
	(zone
		(layer "F.Cu")
		(hatch none 0.5)
		(connect_pads
			(clearance 0)
		)
		(min_thickness 0.25)
		(keepout
			(tracks allowed)
			(vias allowed)
			(pads allowed)
			(copperpour allowed)
			(footprints allowed)
		)
		(placement
			(enabled no)
			(sheetname "")
		)
		(fill
			(thermal_gap 0.5)
			(thermal_bridge_width 0.5)
			(island_removal_mode 0)
		)
		(polygon
			(pts
				(xy 304.319178 -310.166512) (xy 304.319178 -309.722774) (xy 306.644294 -309.722774) (xy 306.644294 -310.166512)
			)
		)
	)
	(zone
		(layer "F.Cu")
		(hatch none 0.5)
		(connect_pads
			(clearance 0)
		)
		(min_thickness 0.25)
		(keepout
			(tracks allowed)
			(vias allowed)
			(pads allowed)
			(copperpour allowed)
			(footprints allowed)
		)
		(placement
			(enabled no)
			(sheetname "")
		)
		(fill
			(thermal_gap 0.5)
			(thermal_bridge_width 0.5)
			(island_removal_mode 0)
		)
		(polygon
			(pts
				(xy 195.510658 -267.554964) (xy 195.510658 -267.326364) (xy 197.542658 -267.326364) (xy 197.542658 -267.554964)
			)
		)
	)
	(zone
		(layer "F.Cu")
		(hatch none 0.5)
		(connect_pads
			(clearance 0)
		)
		(min_thickness 0.25)
		(keepout
			(tracks allowed)
			(vias allowed)
			(pads allowed)
			(copperpour allowed)
			(footprints allowed)
		)
		(placement
			(enabled no)
			(sheetname "")
		)
		(fill
			(thermal_gap 0.5)
			(thermal_bridge_width 0.5)
			(island_removal_mode 0)
		)
		(polygon
			(pts
				(xy 195.510658 -273.276314) (xy 197.542658 -273.276314) (xy 197.542658 -273.2786) (xy 197.721474 -273.2786)
				(xy 197.721474 -273.515836) (xy 197.902576 -273.696938) (xy 197.91807 -273.712432) (xy 197.91807 -273.901408)
				(xy 197.902576 -273.916902) (xy 197.791578 -274.0279) (xy 197.750938 -274.06854) (xy 195.289678 -274.06854)
				(xy 195.148454 -273.927316) (xy 195.148454 -273.730212) (xy 195.229988 -273.648678) (xy 195.288916 -273.58975)
				(xy 195.288916 -273.276314) (xy 195.327524 -273.276314) (xy 195.374514 -273.276314)
			)
		)
	)
	(zone
		(layer "F.Cu")
		(hatch none 0.5)
		(connect_pads
			(clearance 0)
		)
		(min_thickness 0.25)
		(keepout
			(tracks allowed)
			(vias allowed)
			(pads allowed)
			(copperpour allowed)
			(footprints allowed)
		)
		(placement
			(enabled no)
			(sheetname "")
		)
		(fill
			(thermal_gap 0.5)
			(thermal_bridge_width 0.5)
			(island_removal_mode 0)
		)
		(polygon
			(pts
				(xy 84.229702 -247.233186) (xy 84.432648 -247.436132) (xy 84.475828 -247.436132) (xy 84.919566 -246.992394)
				(xy 84.919566 -246.87022) (xy 84.78647 -246.737378) (xy 84.68233 -246.737378) (xy 84.229702 -247.190006)
			)
		)
	)
	(zone
		(layer "F.Cu")
		(hatch none 0.5)
		(connect_pads
			(clearance 0)
		)
		(min_thickness 0.25)
		(keepout
			(tracks allowed)
			(vias allowed)
			(pads allowed)
			(copperpour allowed)
			(footprints allowed)
		)
		(placement
			(enabled no)
			(sheetname "")
		)
		(fill
			(thermal_gap 0.5)
			(thermal_bridge_width 0.5)
			(island_removal_mode 0)
		)
		(polygon
			(pts
				(xy 259.056378 -248.966482) (xy 259.056378 -248.522744) (xy 261.381494 -248.522744) (xy 261.381494 -248.966482)
			)
		)
	)
	(zone
		(layer "F.Cu")
		(hatch none 0.5)
		(connect_pads
			(clearance 0)
		)
		(min_thickness 0.25)
		(keepout
			(tracks allowed)
			(vias allowed)
			(pads allowed)
			(copperpour allowed)
			(footprints allowed)
		)
		(placement
			(enabled no)
			(sheetname "")
		)
		(fill
			(thermal_gap 0.5)
			(thermal_bridge_width 0.5)
			(island_removal_mode 0)
		)
		(polygon
			(pts
				(xy 63.926212 -196.266562) (xy 63.926212 -195.822824) (xy 66.237612 -195.822824) (xy 66.237612 -196.266562)
			)
		)
	)
	(zone
		(layer "F.Cu")
		(hatch none 0.5)
		(connect_pads
			(clearance 0)
		)
		(min_thickness 0.25)
		(keepout
			(tracks allowed)
			(vias allowed)
			(pads allowed)
			(copperpour allowed)
			(footprints allowed)
		)
		(placement
			(enabled no)
			(sheetname "")
		)
		(fill
			(thermal_gap 0.5)
			(thermal_bridge_width 0.5)
			(island_removal_mode 0)
		)
		(polygon
			(pts
				(xy 62.147958 -233.666538) (xy 59.822842 -233.666538) (xy 59.698382 -233.666538) (xy 59.698382 -232.711752)
				(xy 62.206886 -232.711752) (xy 62.206886 -233.666538)
			)
		)
	)
	(zone
		(layer "F.Cu")
		(hatch none 0.5)
		(connect_pads
			(clearance 0)
		)
		(min_thickness 0.25)
		(keepout
			(tracks allowed)
			(vias allowed)
			(pads allowed)
			(copperpour allowed)
			(footprints allowed)
		)
		(placement
			(enabled no)
			(sheetname "")
		)
		(fill
			(thermal_gap 0.5)
			(thermal_bridge_width 0.5)
			(island_removal_mode 0)
		)
		(polygon
			(pts
				(xy 207.154526 -261.376414) (xy 209.186526 -261.376414) (xy 209.186526 -261.605014) (xy 207.154526 -261.605014)
				(xy 206.987902 -261.605014) (xy 206.987902 -261.376414)
			)
		)
	)
	(zone
		(layer "F.Cu")
		(hatch none 0.5)
		(connect_pads
			(clearance 0)
		)
		(min_thickness 0.25)
		(keepout
			(tracks allowed)
			(vias allowed)
			(pads allowed)
			(copperpour allowed)
			(footprints allowed)
		)
		(placement
			(enabled no)
			(sheetname "")
		)
		(fill
			(thermal_gap 0.5)
			(thermal_bridge_width 0.5)
			(island_removal_mode 0)
		)
		(polygon
			(pts
				(xy 274.143978 -230.266494) (xy 274.143978 -229.822756) (xy 276.469094 -229.822756) (xy 276.469094 -230.266494)
			)
		)
	)
	(zone
		(layer "F.Cu")
		(hatch none 0.5)
		(connect_pads
			(clearance 0)
		)
		(min_thickness 0.25)
		(keepout
			(tracks allowed)
			(vias allowed)
			(pads allowed)
			(copperpour allowed)
			(footprints allowed)
		)
		(placement
			(enabled no)
			(sheetname "")
		)
		(fill
			(thermal_gap 0.5)
			(thermal_bridge_width 0.5)
			(island_removal_mode 0)
		)
		(polygon
			(pts
				(xy 78.143862 -340.890352) (xy 78.143862 -344.895932) (xy 78.623922 -345.375992) (xy 80.688942 -345.375992)
				(xy 80.960722 -345.104212) (xy 80.960722 -343.250012) (xy 81.212182 -342.998552) (xy 83.132422 -342.998552)
				(xy 83.548982 -342.581992) (xy 83.548982 -341.091012) (xy 82.901282 -340.443312) (xy 78.590902 -340.443312)
			)
		)
	)
	(zone
		(layer "F.Cu")
		(hatch none 0.5)
		(connect_pads
			(clearance 0)
		)
		(min_thickness 0.25)
		(keepout
			(tracks allowed)
			(vias allowed)
			(pads allowed)
			(copperpour allowed)
			(footprints allowed)
		)
		(placement
			(enabled no)
			(sheetname "")
		)
		(fill
			(thermal_gap 0.5)
			(thermal_bridge_width 0.5)
			(island_removal_mode 0)
		)
		(polygon
			(pts
				(xy 176.979326 -300.476412) (xy 179.011326 -300.476412) (xy 179.011326 -300.705012) (xy 176.979326 -300.705012)
				(xy 176.843182 -300.705012) (xy 176.796192 -300.705012) (xy 176.796192 -300.476412) (xy 176.843182 -300.476412)
			)
		)
	)
	(zone
		(layer "F.Cu")
		(hatch none 0.5)
		(connect_pads
			(clearance 0)
		)
		(min_thickness 0.25)
		(keepout
			(tracks allowed)
			(vias allowed)
			(pads allowed)
			(copperpour allowed)
			(footprints allowed)
		)
		(placement
			(enabled no)
			(sheetname "")
		)
		(fill
			(thermal_gap 0.5)
			(thermal_bridge_width 0.5)
			(island_removal_mode 0)
		)
		(polygon
			(pts
				(xy 259.056378 -196.266562) (xy 259.056378 -195.822824) (xy 261.381494 -195.822824) (xy 261.381494 -196.266562)
			)
		)
	)
	(zone
		(layer "F.Cu")
		(hatch none 0.5)
		(connect_pads
			(clearance 0)
		)
		(min_thickness 0.25)
		(keepout
			(tracks allowed)
			(vias allowed)
			(pads allowed)
			(copperpour allowed)
			(footprints allowed)
		)
		(placement
			(enabled no)
			(sheetname "")
		)
		(fill
			(thermal_gap 0.5)
			(thermal_bridge_width 0.5)
			(island_removal_mode 0)
		)
		(polygon
			(pts
				(xy 289.231578 -207.316578) (xy 289.231578 -206.87284) (xy 291.556694 -206.87284) (xy 291.556694 -207.316578)
			)
		)
	)
	(zone
		(layer "F.Cu")
		(hatch none 0.5)
		(connect_pads
			(clearance 0)
		)
		(min_thickness 0.25)
		(keepout
			(tracks not_allowed)
			(vias allowed)
			(pads allowed)
			(copperpour not_allowed)
			(footprints allowed)
		)
		(placement
			(enabled no)
			(sheetname "")
		)
		(fill
			(thermal_gap 0.5)
			(thermal_bridge_width 0.5)
			(island_removal_mode 0)
		)
		(polygon
			(pts
				(xy 119.434864 -335.356708) (xy 119.67718 -335.356708) (xy 119.67718 -334.358488) (xy 119.434864 -334.358488)
			)
		)
	)
	(zone
		(layer "F.Cu")
		(hatch none 0.5)
		(connect_pads
			(clearance 0)
		)
		(min_thickness 0.25)
		(keepout
			(tracks allowed)
			(vias allowed)
			(pads allowed)
			(copperpour allowed)
			(footprints allowed)
		)
		(placement
			(enabled no)
			(sheetname "")
		)
		(fill
			(thermal_gap 0.5)
			(thermal_bridge_width 0.5)
			(island_removal_mode 0)
		)
		(polygon
			(pts
				(xy 277.58771 -217.516456) (xy 277.58771 -217.072718) (xy 279.912826 -217.072718) (xy 279.912826 -217.516456)
			)
		)
	)
	(zone
		(layer "F.Cu")
		(hatch none 0.5)
		(connect_pads
			(clearance 0)
		)
		(min_thickness 0.25)
		(keepout
			(tracks allowed)
			(vias allowed)
			(pads allowed)
			(copperpour allowed)
			(footprints allowed)
		)
		(placement
			(enabled no)
			(sheetname "")
		)
		(fill
			(thermal_gap 0.5)
			(thermal_bridge_width 0.5)
			(island_removal_mode 0)
		)
		(polygon
			(pts
				(xy 443.450726 -282.854908) (xy 443.450726 -282.626308) (xy 445.482726 -282.626308) (xy 445.482726 -282.854908)
			)
		)
	)
	(zone
		(layer "F.Cu")
		(hatch none 0.5)
		(connect_pads
			(clearance 0)
		)
		(min_thickness 0.25)
		(keepout
			(tracks allowed)
			(vias allowed)
			(pads allowed)
			(copperpour allowed)
			(footprints not_allowed)
		)
		(placement
			(enabled no)
			(sheetname "")
		)
		(fill
			(thermal_gap 0.5)
			(thermal_bridge_width 0.5)
			(island_removal_mode 0)
		)
		(polygon
			(pts
				(arc
					(start 446.300098 -435.600094)
					(mid 448.80022 -433.099972)
					(end 451.300088 -435.600094)
				)
				(arc
					(start 451.300088 -435.600094)
					(mid 448.80022 -438.099962)
					(end 446.300098 -435.600094)
				)
			)
		)
	)
	(zone
		(layer "F.Cu")
		(hatch none 0.5)
		(connect_pads
			(clearance 0)
		)
		(min_thickness 0.25)
		(keepout
			(tracks allowed)
			(vias allowed)
			(pads allowed)
			(copperpour allowed)
			(footprints allowed)
		)
		(placement
			(enabled no)
			(sheetname "")
		)
		(fill
			(thermal_gap 0.5)
			(thermal_bridge_width 0.5)
			(island_removal_mode 0)
		)
		(polygon
			(pts
				(xy 409.831794 -219.954856) (xy 409.831794 -219.726256) (xy 411.863794 -219.726256) (xy 411.863794 -219.954856)
			)
		)
	)
	(zone
		(layer "F.Cu")
		(hatch none 0.5)
		(connect_pads
			(clearance 0)
		)
		(min_thickness 0.25)
		(keepout
			(tracks allowed)
			(vias allowed)
			(pads allowed)
			(copperpour allowed)
			(footprints allowed)
		)
		(placement
			(enabled no)
			(sheetname "")
		)
		(fill
			(thermal_gap 0.5)
			(thermal_bridge_width 0.5)
			(island_removal_mode 0)
		)
		(polygon
			(pts
				(xy 59.822842 -209.0166) (xy 59.822842 -208.572862) (xy 62.147958 -208.572862) (xy 62.147958 -209.0166)
			)
		)
	)
	(zone
		(layer "F.Cu")
		(hatch none 0.5)
		(connect_pads
			(clearance 0)
		)
		(min_thickness 0.25)
		(keepout
			(tracks allowed)
			(vias allowed)
			(pads allowed)
			(copperpour allowed)
			(footprints allowed)
		)
		(placement
			(enabled no)
			(sheetname "")
		)
		(fill
			(thermal_gap 0.5)
			(thermal_bridge_width 0.5)
			(island_removal_mode 0)
		)
		(polygon
			(pts
				(xy 292.67531 -277.866602) (xy 292.67531 -277.422864) (xy 295.000426 -277.422864) (xy 295.000426 -277.866602)
			)
		)
	)
	(zone
		(layer "F.Cu")
		(hatch none 0.5)
		(connect_pads
			(clearance 0)
		)
		(min_thickness 0.25)
		(keepout
			(tracks allowed)
			(vias allowed)
			(pads allowed)
			(copperpour allowed)
			(footprints allowed)
		)
		(placement
			(enabled no)
			(sheetname "")
		)
		(fill
			(thermal_gap 0.5)
			(thermal_bridge_width 0.5)
			(island_removal_mode 0)
		)
		(polygon
			(pts
				(xy 51.14036 -6.137148) (xy 51.14036 -4.064508) (xy 53.26888 -4.064508) (xy 53.26888 -6.137148)
			)
		)
	)
	(zone
		(layer "F.Cu")
		(hatch none 0.5)
		(connect_pads
			(clearance 0)
		)
		(min_thickness 0.25)
		(keepout
			(tracks not_allowed)
			(vias allowed)
			(pads allowed)
			(copperpour not_allowed)
			(footprints allowed)
		)
		(placement
			(enabled no)
			(sheetname "")
		)
		(fill
			(thermal_gap 0.5)
			(thermal_bridge_width 0.5)
			(island_removal_mode 0)
		)
		(polygon
			(pts
				(arc
					(start 382.858772 -354.434902)
					(mid 384.458972 -352.834702)
					(end 386.058918 -354.434902)
				)
				(arc
					(start 386.058918 -354.434902)
					(mid 384.458972 -356.034848)
					(end 382.858772 -354.434902)
				)
			)
		)
	)
	(zone
		(layer "F.Cu")
		(hatch none 0.5)
		(connect_pads
			(clearance 0)
		)
		(min_thickness 0.25)
		(keepout
			(tracks allowed)
			(vias allowed)
			(pads allowed)
			(copperpour allowed)
			(footprints allowed)
		)
		(placement
			(enabled no)
			(sheetname "")
		)
		(fill
			(thermal_gap 0.5)
			(thermal_bridge_width 0.5)
			(island_removal_mode 0)
		)
		(polygon
			(pts
				(xy 455.094594 -309.826406) (xy 457.126594 -309.826406) (xy 457.126594 -310.055006) (xy 455.094594 -310.055006)
				(xy 454.95845 -310.055006) (xy 454.91146 -310.055006) (xy 454.91146 -309.826406) (xy 454.95845 -309.826406)
			)
		)
	)
	(zone
		(layer "F.Cu")
		(hatch none 0.5)
		(connect_pads
			(clearance 0)
		)
		(min_thickness 0.25)
		(keepout
			(tracks allowed)
			(vias allowed)
			(pads allowed)
			(copperpour allowed)
			(footprints allowed)
		)
		(placement
			(enabled no)
			(sheetname "")
		)
		(fill
			(thermal_gap 0.5)
			(thermal_bridge_width 0.5)
			(island_removal_mode 0)
		)
		(polygon
			(pts
				(xy 14.560042 -264.266426) (xy 14.560042 -263.822688) (xy 16.885158 -263.822688) (xy 16.885158 -264.266426)
			)
		)
	)
	(zone
		(layer "F.Cu")
		(hatch none 0.5)
		(connect_pads
			(clearance 0)
		)
		(min_thickness 0.25)
		(keepout
			(tracks allowed)
			(vias allowed)
			(pads allowed)
			(copperpour allowed)
			(footprints allowed)
		)
		(placement
			(enabled no)
			(sheetname "")
		)
		(fill
			(thermal_gap 0.5)
			(thermal_bridge_width 0.5)
			(island_removal_mode 0)
		)
		(polygon
			(pts
				(xy 455.094594 -209.75701) (xy 457.126594 -209.75701) (xy 457.126594 -209.52841) (xy 455.094594 -209.52841)
				(xy 454.963276 -209.52841) (xy 454.937368 -209.52841) (xy 454.937368 -209.75701) (xy 454.963276 -209.75701)
			)
		)
	)
	(zone
		(layer "F.Cu")
		(hatch none 0.5)
		(connect_pads
			(clearance 0)
		)
		(min_thickness 0.25)
		(keepout
			(tracks allowed)
			(vias allowed)
			(pads allowed)
			(copperpour allowed)
			(footprints not_allowed)
		)
		(placement
			(enabled no)
			(sheetname "")
		)
		(fill
			(thermal_gap 0.5)
			(thermal_bridge_width 0.5)
			(island_removal_mode 0)
		)
		(polygon
			(pts
				(xy 210.620102 -330.091796) (xy 216.719912 -330.091796) (xy 216.719912 -186.09183) (xy 210.620102 -186.09183)
			)
		)
	)
	(zone
		(layer "F.Cu")
		(hatch none 0.5)
		(connect_pads
			(clearance 0)
		)
		(min_thickness 0.25)
		(keepout
			(tracks allowed)
			(vias allowed)
			(pads allowed)
			(copperpour allowed)
			(footprints not_allowed)
		)
		(placement
			(enabled no)
			(sheetname "")
		)
		(fill
			(thermal_gap 0.5)
			(thermal_bridge_width 0.5)
			(island_removal_mode 0)
		)
		(polygon
			(pts
				(arc
					(start 7.53999 -160.50006)
					(mid 10.340086 -157.699964)
					(end 13.139928 -160.50006)
				)
				(arc
					(start 13.139928 -160.50006)
					(mid 10.340086 -163.299902)
					(end 7.53999 -160.50006)
				)
			)
		)
	)
	(zone
		(layer "F.Cu")
		(hatch none 0.5)
		(connect_pads
			(clearance 0)
		)
		(min_thickness 0.25)
		(keepout
			(tracks allowed)
			(vias allowed)
			(pads allowed)
			(copperpour allowed)
			(footprints allowed)
		)
		(placement
			(enabled no)
			(sheetname "")
		)
		(fill
			(thermal_gap 0.5)
			(thermal_bridge_width 0.5)
			(island_removal_mode 0)
		)
		(polygon
			(pts
				(xy 428.363126 -199.554846) (xy 428.363126 -199.326246) (xy 430.395126 -199.326246) (xy 430.395126 -199.554846)
			)
		)
	)
	(zone
		(layer "F.Cu")
		(hatch none 0.5)
		(connect_pads
			(clearance 0)
		)
		(min_thickness 0.25)
		(keepout
			(tracks allowed)
			(vias allowed)
			(pads allowed)
			(copperpour allowed)
			(footprints allowed)
		)
		(placement
			(enabled no)
			(sheetname "")
		)
		(fill
			(thermal_gap 0.5)
			(thermal_bridge_width 0.5)
			(island_removal_mode 0)
		)
		(polygon
			(pts
				(xy 210.598258 -202.105006) (xy 210.598258 -201.876406) (xy 212.630258 -201.876406) (xy 212.630258 -202.105006)
			)
		)
	)
	(zone
		(layer "F.Cu")
		(hatch none 0.5)
		(connect_pads
			(clearance 0)
		)
		(min_thickness 0.25)
		(keepout
			(tracks allowed)
			(vias allowed)
			(pads allowed)
			(copperpour allowed)
			(footprints allowed)
		)
		(placement
			(enabled no)
			(sheetname "")
		)
		(fill
			(thermal_gap 0.5)
			(thermal_bridge_width 0.5)
			(island_removal_mode 0)
		)
		(polygon
			(pts
				(xy 424.919394 -228.456998) (xy 426.951394 -228.456998) (xy 426.951394 -228.228398) (xy 424.919394 -228.228398)
				(xy 424.788076 -228.228398) (xy 424.762168 -228.228398) (xy 424.762168 -228.456998) (xy 424.788076 -228.456998)
			)
		)
	)
	(zone
		(layer "F.Cu")
		(hatch none 0.5)
		(connect_pads
			(clearance 0)
		)
		(min_thickness 0.25)
		(keepout
			(tracks allowed)
			(vias allowed)
			(pads allowed)
			(copperpour allowed)
			(footprints allowed)
		)
		(placement
			(enabled no)
			(sheetname "")
		)
		(fill
			(thermal_gap 0.5)
			(thermal_bridge_width 0.5)
			(island_removal_mode 0)
		)
		(polygon
			(pts
				(xy 11.11631 -291.466524) (xy 11.11631 -291.022786) (xy 13.441426 -291.022786) (xy 13.441426 -291.466524)
			)
		)
	)
	(zone
		(layer "F.Cu")
		(hatch none 0.5)
		(connect_pads
			(clearance 0)
		)
		(min_thickness 0.25)
		(keepout
			(tracks allowed)
			(vias allowed)
			(pads allowed)
			(copperpour allowed)
			(footprints allowed)
		)
		(placement
			(enabled no)
			(sheetname "")
		)
		(fill
			(thermal_gap 0.5)
			(thermal_bridge_width 0.5)
			(island_removal_mode 0)
		)
		(polygon
			(pts
				(xy 334.244188 -335.09966) (xy 334.244188 -339.10524) (xy 334.724248 -339.5853) (xy 336.789268 -339.5853)
				(xy 337.061048 -339.31352) (xy 337.061048 -337.45932) (xy 337.312508 -337.20786) (xy 339.232748 -337.20786)
				(xy 339.649308 -336.7913) (xy 339.649308 -335.30032) (xy 339.001608 -334.65262) (xy 334.691228 -334.65262)
			)
		)
	)
	(zone
		(layer "F.Cu")
		(hatch none 0.5)
		(connect_pads
			(clearance 0)
		)
		(min_thickness 0.25)
		(keepout
			(tracks allowed)
			(vias allowed)
			(pads allowed)
			(copperpour allowed)
			(footprints allowed)
		)
		(placement
			(enabled no)
			(sheetname "")
		)
		(fill
			(thermal_gap 0.5)
			(thermal_bridge_width 0.5)
			(island_removal_mode 0)
		)
		(polygon
			(pts
				(xy 157.791658 -271.576546) (xy 159.823658 -271.576546) (xy 159.823658 -271.578832) (xy 160.002474 -271.578832)
				(xy 160.183576 -271.578832) (xy 160.211008 -271.578832) (xy 160.211008 -272.368772) (xy 160.110932 -272.368772)
				(xy 157.570678 -272.368772) (xy 157.386782 -272.368772) (xy 157.386782 -271.576546) (xy 157.429454 -271.576546)
				(xy 157.510988 -271.576546) (xy 157.608524 -271.576546) (xy 157.655514 -271.576546)
			)
		)
	)
	(zone
		(layer "F.Cu")
		(hatch none 0.5)
		(connect_pads
			(clearance 0)
		)
		(min_thickness 0.25)
		(keepout
			(tracks allowed)
			(vias allowed)
			(pads allowed)
			(copperpour allowed)
			(footprints allowed)
		)
		(placement
			(enabled no)
			(sheetname "")
		)
		(fill
			(thermal_gap 0.5)
			(thermal_bridge_width 0.5)
			(island_removal_mode 0)
		)
		(polygon
			(pts
				(xy 52.65674 -156.469588) (xy 52.65674 -154.722068) (xy 54.59222 -154.722068) (xy 54.59222 -156.469588)
			)
		)
	)
	(zone
		(layer "F.Cu")
		(hatch none 0.5)
		(connect_pads
			(clearance 0)
		)
		(min_thickness 0.25)
		(keepout
			(tracks allowed)
			(vias allowed)
			(pads allowed)
			(copperpour allowed)
			(footprints allowed)
		)
		(placement
			(enabled no)
			(sheetname "")
		)
		(fill
			(thermal_gap 0.5)
			(thermal_bridge_width 0.5)
			(island_removal_mode 0)
		)
		(polygon
			(pts
				(xy 259.056378 -231.966516) (xy 259.056378 -231.522778) (xy 261.381494 -231.522778) (xy 261.381494 -231.966516)
			)
		)
	)
	(zone
		(layer "F.Cu")
		(hatch none 0.5)
		(connect_pads
			(clearance 0)
		)
		(min_thickness 0.25)
		(keepout
			(tracks allowed)
			(vias allowed)
			(pads allowed)
			(copperpour allowed)
			(footprints allowed)
		)
		(placement
			(enabled no)
			(sheetname "")
		)
		(fill
			(thermal_gap 0.5)
			(thermal_bridge_width 0.5)
			(island_removal_mode 0)
		)
		(polygon
			(pts
				(xy 440.006994 -212.926422) (xy 442.038994 -212.926422) (xy 442.038994 -213.155022) (xy 440.006994 -213.155022)
				(xy 439.87085 -213.155022) (xy 439.82386 -213.155022) (xy 439.82386 -212.926422) (xy 439.87085 -212.926422)
			)
		)
	)
	(zone
		(layer "F.Cu")
		(hatch none 0.5)
		(connect_pads
			(clearance 0)
		)
		(min_thickness 0.25)
		(keepout
			(tracks allowed)
			(vias allowed)
			(pads allowed)
			(copperpour allowed)
			(footprints allowed)
		)
		(placement
			(enabled no)
			(sheetname "")
		)
		(fill
			(thermal_gap 0.5)
			(thermal_bridge_width 0.5)
			(island_removal_mode 0)
		)
		(polygon
			(pts
				(xy 11.11631 -295.716452) (xy 11.11631 -295.272714) (xy 13.441426 -295.272714) (xy 13.441426 -295.716452)
			)
		)
	)
	(zone
		(layer "F.Cu")
		(hatch none 0.5)
		(connect_pads
			(clearance 0)
		)
		(min_thickness 0.25)
		(keepout
			(tracks allowed)
			(vias allowed)
			(pads allowed)
			(copperpour allowed)
			(footprints allowed)
		)
		(placement
			(enabled no)
			(sheetname "")
		)
		(fill
			(thermal_gap 0.5)
			(thermal_bridge_width 0.5)
			(island_removal_mode 0)
		)
		(polygon
			(pts
				(xy 176.979326 -289.426396) (xy 179.011326 -289.426396) (xy 179.011326 -289.654996) (xy 176.979326 -289.654996)
				(xy 176.843182 -289.654996) (xy 176.796192 -289.654996) (xy 176.796192 -289.426396) (xy 176.843182 -289.426396)
			)
		)
	)
	(zone
		(layer "F.Cu")
		(hatch none 0.5)
		(connect_pads
			(clearance 0)
		)
		(min_thickness 0.25)
		(keepout
			(tracks allowed)
			(vias allowed)
			(pads allowed)
			(copperpour allowed)
			(footprints allowed)
		)
		(placement
			(enabled no)
			(sheetname "")
		)
		(fill
			(thermal_gap 0.5)
			(thermal_bridge_width 0.5)
			(island_removal_mode 0)
		)
		(polygon
			(pts
				(xy 458.538326 -222.505016) (xy 458.538326 -222.276416) (xy 460.570326 -222.276416) (xy 460.570326 -222.505016)
			)
		)
	)
	(zone
		(layer "F.Cu")
		(hatch none 0.5)
		(connect_pads
			(clearance 0)
		)
		(min_thickness 0.25)
		(keepout
			(tracks allowed)
			(vias allowed)
			(pads allowed)
			(copperpour allowed)
			(footprints allowed)
		)
		(placement
			(enabled no)
			(sheetname "")
		)
		(fill
			(thermal_gap 0.5)
			(thermal_bridge_width 0.5)
			(island_removal_mode 0)
		)
		(polygon
			(pts
				(xy 161.891726 -303.026318) (xy 163.923726 -303.026318) (xy 163.923726 -303.254918) (xy 163.923726 -304.097944)
				(xy 161.69386 -304.097944) (xy 161.69386 -303.026318)
			)
		)
	)
	(zone
		(layer "F.Cu")
		(hatch none 0.5)
		(connect_pads
			(clearance 0)
		)
		(min_thickness 0.25)
		(keepout
			(tracks allowed)
			(vias allowed)
			(pads allowed)
			(copperpour allowed)
			(footprints allowed)
		)
		(placement
			(enabled no)
			(sheetname "")
		)
		(fill
			(thermal_gap 0.5)
			(thermal_bridge_width 0.5)
			(island_removal_mode 0)
		)
		(polygon
			(pts
				(xy 14.921484 -20.962874) (xy 14.921484 -19.404838) (xy 16.465042 -19.404838) (xy 16.465042 -20.962874)
			)
		)
	)
	(zone
		(layer "F.Cu")
		(hatch none 0.5)
		(connect_pads
			(clearance 0)
		)
		(min_thickness 0.25)
		(keepout
			(tracks allowed)
			(vias allowed)
			(pads allowed)
			(copperpour allowed)
			(footprints allowed)
		)
		(placement
			(enabled no)
			(sheetname "")
		)
		(fill
			(thermal_gap 0.5)
			(thermal_bridge_width 0.5)
			(island_removal_mode 0)
		)
		(polygon
			(pts
				(xy 17.851882 -20.10791) (xy 17.851882 -16.973296) (xy 19.630644 -16.973296) (xy 19.630644 -20.10791)
			)
		)
	)
	(zone
		(layer "F.Cu")
		(hatch none 0.5)
		(connect_pads
			(clearance 0)
		)
		(min_thickness 0.25)
		(keepout
			(tracks allowed)
			(vias allowed)
			(pads allowed)
			(copperpour allowed)
			(footprints allowed)
		)
		(placement
			(enabled no)
			(sheetname "")
		)
		(fill
			(thermal_gap 0.5)
			(thermal_bridge_width 0.5)
			(island_removal_mode 0)
		)
		(polygon
			(pts
				(xy 59.806586 -315.288422) (xy 59.806586 -314.844684) (xy 62.131702 -314.844684) (xy 62.131702 -315.288422)
			)
		)
	)
	(zone
		(layer "F.Cu")
		(hatch none 0.5)
		(connect_pads
			(clearance 0)
		)
		(min_thickness 0.25)
		(keepout
			(tracks allowed)
			(vias allowed)
			(pads allowed)
			(copperpour allowed)
			(footprints allowed)
		)
		(placement
			(enabled no)
			(sheetname "")
		)
		(fill
			(thermal_gap 0.5)
			(thermal_bridge_width 0.5)
			(island_removal_mode 0)
		)
		(polygon
			(pts
				(xy 440.006994 -312.606944) (xy 442.038994 -312.606944) (xy 442.038994 -312.378344) (xy 440.006994 -312.378344)
				(xy 439.875676 -312.378344) (xy 439.849768 -312.378344) (xy 439.849768 -312.606944) (xy 439.875676 -312.606944)
			)
		)
	)
	(zone
		(layer "F.Cu")
		(hatch none 0.5)
		(connect_pads
			(clearance 0)
		)
		(min_thickness 0.25)
		(keepout
			(tracks allowed)
			(vias allowed)
			(pads allowed)
			(copperpour allowed)
			(footprints allowed)
		)
		(placement
			(enabled no)
			(sheetname "")
		)
		(fill
			(thermal_gap 0.5)
			(thermal_bridge_width 0.5)
			(island_removal_mode 0)
		)
		(polygon
			(pts
				(xy 68.965572 -404.802594) (xy 68.965572 -399.959576) (xy 70.849998 -399.959576) (xy 70.849998 -404.802594)
			)
		)
	)
	(zone
		(layer "F.Cu")
		(hatch none 0.5)
		(connect_pads
			(clearance 0)
		)
		(min_thickness 0.25)
		(keepout
			(tracks allowed)
			(vias allowed)
			(pads allowed)
			(copperpour allowed)
			(footprints allowed)
		)
		(placement
			(enabled no)
			(sheetname "")
		)
		(fill
			(thermal_gap 0.5)
			(thermal_bridge_width 0.5)
			(island_removal_mode 0)
		)
		(polygon
			(pts
				(xy 26.20391 -313.566556) (xy 26.20391 -313.122818) (xy 28.529026 -313.122818) (xy 28.529026 -313.566556)
			)
		)
	)
	(zone
		(layer "F.Cu")
		(hatch none 0.5)
		(connect_pads
			(clearance 0)
		)
		(min_thickness 0.25)
		(keepout
			(tracks allowed)
			(vias allowed)
			(pads allowed)
			(copperpour allowed)
			(footprints allowed)
		)
		(placement
			(enabled no)
			(sheetname "")
		)
		(fill
			(thermal_gap 0.5)
			(thermal_bridge_width 0.5)
			(island_removal_mode 0)
		)
		(polygon
			(pts
				(xy 26.20391 -294.01643) (xy 26.20391 -293.572692) (xy 28.529026 -293.572692) (xy 28.529026 -294.01643)
			)
		)
	)
	(zone
		(layer "F.Cu")
		(hatch none 0.5)
		(connect_pads
			(clearance 0)
		)
		(min_thickness 0.25)
		(keepout
			(tracks allowed)
			(vias allowed)
			(pads allowed)
			(copperpour allowed)
			(footprints allowed)
		)
		(placement
			(enabled no)
			(sheetname "")
		)
		(fill
			(thermal_gap 0.5)
			(thermal_bridge_width 0.5)
			(island_removal_mode 0)
		)
		(polygon
			(pts
				(xy 49.1998 -13.129768) (xy 49.1998 -10.391648) (xy 59.7027 -10.391648) (xy 59.7027 -13.129768)
			)
		)
	)
	(zone
		(layer "F.Cu")
		(hatch none 0.5)
		(connect_pads
			(clearance 0)
		)
		(min_thickness 0.25)
		(keepout
			(tracks allowed)
			(vias allowed)
			(pads allowed)
			(copperpour allowed)
			(footprints allowed)
		)
		(placement
			(enabled no)
			(sheetname "")
		)
		(fill
			(thermal_gap 0.5)
			(thermal_bridge_width 0.5)
			(island_removal_mode 0)
		)
		(polygon
			(pts
				(xy 14.560042 -221.766638) (xy 14.560042 -221.3229) (xy 16.885158 -221.3229) (xy 16.885158 -221.766638)
			)
		)
	)
	(zone
		(layer "F.Cu")
		(hatch none 0.5)
		(connect_pads
			(clearance 0)
		)
		(min_thickness 0.25)
		(keepout
			(tracks allowed)
			(vias allowed)
			(pads allowed)
			(copperpour allowed)
			(footprints allowed)
		)
		(placement
			(enabled no)
			(sheetname "")
		)
		(fill
			(thermal_gap 0.5)
			(thermal_bridge_width 0.5)
			(island_removal_mode 0)
		)
		(polygon
			(pts
				(xy 116.08308 -411.147768) (xy 116.08308 -416.641788) (xy 109.01934 -416.641788) (xy 109.01934 -411.147768)
			)
		)
	)
	(zone
		(layer "F.Cu")
		(hatch none 0.5)
		(connect_pads
			(clearance 0)
		)
		(min_thickness 0.25)
		(keepout
			(tracks allowed)
			(vias allowed)
			(pads allowed)
			(copperpour allowed)
			(footprints not_allowed)
		)
		(placement
			(enabled no)
			(sheetname "")
		)
		(fill
			(thermal_gap 0.5)
			(thermal_bridge_width 0.5)
			(island_removal_mode 0)
		)
		(polygon
			(pts
				(xy 364.16488 -261.62) (xy 367.795048 -261.62) (xy 367.795048 -237.00994) (xy 364.16488 -237.00994)
			)
		)
	)
	(zone
		(layer "F.Cu")
		(hatch none 0.5)
		(connect_pads
			(clearance 0)
		)
		(min_thickness 0.25)
		(keepout
			(tracks allowed)
			(vias allowed)
			(pads allowed)
			(copperpour allowed)
			(footprints allowed)
		)
		(placement
			(enabled no)
			(sheetname "")
		)
		(fill
			(thermal_gap 0.5)
			(thermal_bridge_width 0.5)
			(island_removal_mode 0)
		)
		(polygon
			(pts
				(xy 440.006994 -266.476226) (xy 442.038994 -266.476226) (xy 442.038994 -266.704826) (xy 440.006994 -266.704826)
				(xy 439.84037 -266.704826) (xy 439.84037 -266.476226)
			)
		)
	)
	(zone
		(layer "F.Cu")
		(hatch none 0.5)
		(connect_pads
			(clearance 0)
		)
		(min_thickness 0.25)
		(keepout
			(tracks allowed)
			(vias allowed)
			(pads allowed)
			(copperpour allowed)
			(footprints allowed)
		)
		(placement
			(enabled no)
			(sheetname "")
		)
		(fill
			(thermal_gap 0.5)
			(thermal_bridge_width 0.5)
			(island_removal_mode 0)
		)
		(polygon
			(pts
				(xy 85.607906 -252.981968) (xy 86.353142 -252.981968) (xy 86.893654 -253.52248) (xy 86.893654 -253.868682)
				(xy 88.017858 -254.992886) (xy 88.018112 -268.515846) (xy 87.051642 -269.482316) (xy 87.051642 -270.280638)
				(xy 87.499698 -270.728694) (xy 87.499698 -271.084802) (xy 88.00338 -271.588484) (xy 88.00338 -273.424904)
				(xy 86.50224 -274.926044) (xy 86.50224 -275.3995) (xy 86.916768 -275.813774) (xy 87.938102 -275.813774)
				(xy 89.101422 -276.977094) (xy 89.663524 -276.977094) (xy 90.42781 -277.74138) (xy 90.42781 -278.07412)
				(xy 90.16365 -278.33828) (xy 88.606122 -278.33828) (xy 88.459818 -278.484584) (xy 88.459818 -278.849836)
				(xy 88.075516 -279.234138) (xy 87.209376 -279.234138) (xy 87.100918 -279.342596) (xy 86.579202 -279.342596)
				(xy 86.4616 -279.224994) (xy 86.201504 -279.224994) (xy 86.105238 -279.32126) (xy 86.105238 -279.65908)
				(xy 85.62213 -280.141934) (xy 85.533738 -280.141934) (xy 85.346286 -279.954482) (xy 85.346286 -279.8826)
				(xy 85.229446 -279.76576) (xy 84.954364 -279.76576) (xy 84.894166 -279.825958) (xy 84.723732 -279.825958)
				(xy 84.598256 -279.700482) (xy 84.567522 -279.700482) (xy 84.471764 -279.700482) (xy 84.065364 -279.294082)
				(xy 84.065364 -279.199848) (xy 84.243164 -279.022302) (xy 84.243164 -278.940768) (xy 83.89239 -278.589994)
				(xy 83.82889 -278.589994) (xy 83.65617 -278.762714) (xy 83.565492 -278.762714) (xy 82.58556 -277.782782)
				(xy 82.58556 -277.664164) (xy 84.650072 -275.599652) (xy 84.650072 -275.500338) (xy 83.787234 -274.6375)
				(xy 83.625182 -274.6375) (xy 83.246722 -274.25904) (xy 83.246722 -274.15871) (xy 83.46694 -273.938492)
				(xy 83.46694 -273.872198) (xy 83.14563 -273.550888) (xy 83.14563 -273.444716) (xy 83.2993 -273.291046)
				(xy 83.2993 -273.228816) (xy 83.102958 -273.032474) (xy 83.102958 -272.964148) (xy 84.327746 -271.73936)
				(xy 84.327746 -271.72158) (xy 84.176108 -271.569942) (xy 84.176108 -271.498314) (xy 84.624164 -271.050258)
				(xy 84.624164 -271.010634) (xy 84.205826 -270.592296) (xy 84.205826 -270.218662) (xy 83.593686 -269.606522)
				(xy 83.593686 -269.52067) (xy 83.951064 -269.163292) (xy 83.951064 -269.129764) (xy 83.79841 -268.97711)
				(xy 83.772248 -268.97711) (xy 83.222084 -269.527274) (xy 83.123024 -269.527274) (xy 82.753962 -269.158212)
				(xy 82.753962 -269.047468) (xy 83.388708 -268.412722) (xy 83.388708 -268.353286) (xy 83.02371 -267.988288)
				(xy 83.02371 -267.885164) (xy 83.331304 -267.57757) (xy 83.331304 -267.519912) (xy 83.172554 -267.361162)
				(xy 83.172554 -267.327888) (xy 83.247992 -267.25245) (xy 83.717892 -266.78255) (xy 83.989418 -266.511024)
				(xy 83.989418 -265.94181) (xy 83.773518 -265.72591) (xy 83.773518 -264.791952) (xy 83.696048 -264.714482)
				(xy 82.771996 -264.714482) (xy 82.533998 -264.476484) (xy 82.533998 -264.311892) (xy 82.601308 -264.244582)
				(xy 82.601308 -264.188702) (xy 82.45475 -264.042144) (xy 82.45475 -263.958832) (xy 82.551778 -263.861804)
				(xy 82.551778 -263.786366) (xy 82.414872 -263.64946) (xy 82.414872 -263.56437) (xy 82.557874 -263.421368)
				(xy 83.705954 -263.421368) (xy 83.745578 -263.381744) (xy 83.745578 -263.220962) (xy 83.703922 -263.179306)
				(xy 82.704432 -263.179306) (xy 82.609182 -263.084056) (xy 82.609182 -262.471662) (xy 82.700368 -262.380476)
				(xy 82.92846 -262.380476) (xy 82.9564 -262.352536) (xy 82.9564 -261.914132) (xy 82.916776 -261.874508)
				(xy 82.654902 -261.874508) (xy 82.599276 -261.818882) (xy 82.599276 -261.430262) (xy 82.67446 -261.355078)
				(xy 83.710018 -261.355078) (xy 83.733894 -261.378954) (xy 83.818984 -261.378954) (xy 83.932014 -261.265924)
				(xy 83.932014 -261.204456) (xy 83.850734 -261.123176) (xy 83.339178 -261.123176) (xy 83.279742 -261.06374)
				(xy 83.279742 -260.02234) (xy 83.374992 -259.92709) (xy 83.500214 -259.92709) (xy 83.678522 -259.748782)
				(xy 83.678522 -259.562092) (xy 83.736942 -259.503672) (xy 83.736942 -258.836922) (xy 83.626452 -258.726432)
				(xy 83.626452 -258.542028) (xy 83.665822 -258.502658) (xy 83.665822 -258.485132) (xy 83.53933 -258.358894)
				(xy 83.53933 -258.315206) (xy 83.57489 -258.279646) (xy 83.57489 -258.142486) (xy 83.483704 -258.0513)
				(xy 83.483704 -257.991102) (xy 83.553046 -257.92176) (xy 83.619086 -257.85572) (xy 83.796886 -257.67792)
				(xy 85.026754 -257.67792) (xy 85.12175 -257.582924) (xy 85.12175 -257.394964) (xy 84.979002 -257.252216)
				(xy 84.674456 -257.252216) (xy 84.589366 -257.167126) (xy 84.589366 -257.02006) (xy 84.569808 -257.000502)
				(xy 84.307172 -257.000502) (xy 84.18576 -256.87909) (xy 84.18576 -256.336038) (xy 82.791808 -254.942086)
				(xy 82.791808 -254.746252) (xy 82.841338 -254.696722) (xy 82.862674 -254.675386) (xy 84.271358 -253.266448)
				(xy 85.323426 -253.266448) (xy 85.392006 -253.197868)
			)
		)
	)
	(zone
		(layer "F.Cu")
		(hatch none 0.5)
		(connect_pads
			(clearance 0)
		)
		(min_thickness 0.25)
		(keepout
			(tracks allowed)
			(vias allowed)
			(pads allowed)
			(copperpour allowed)
			(footprints allowed)
		)
		(placement
			(enabled no)
			(sheetname "")
		)
		(fill
			(thermal_gap 0.5)
			(thermal_bridge_width 0.5)
			(island_removal_mode 0)
		)
		(polygon
			(pts
				(xy 378.438664 -410.948886) (xy 378.438664 -406.105868) (xy 380.32309 -406.105868) (xy 380.32309 -410.948886)
			)
		)
	)
	(zone
		(layer "F.Cu")
		(hatch none 0.5)
		(connect_pads
			(clearance 0)
		)
		(min_thickness 0.25)
		(keepout
			(tracks allowed)
			(vias allowed)
			(pads allowed)
			(copperpour allowed)
			(footprints allowed)
		)
		(placement
			(enabled no)
			(sheetname "")
		)
		(fill
			(thermal_gap 0.5)
			(thermal_bridge_width 0.5)
			(island_removal_mode 0)
		)
		(polygon
			(pts
				(xy 380.155704 -404.802594) (xy 380.155704 -399.959576) (xy 382.04013 -399.959576) (xy 382.04013 -404.802594)
			)
		)
	)
	(zone
		(layer "F.Cu")
		(hatch none 0.5)
		(connect_pads
			(clearance 0)
		)
		(min_thickness 0.25)
		(keepout
			(tracks allowed)
			(vias allowed)
			(pads allowed)
			(copperpour allowed)
			(footprints allowed)
		)
		(placement
			(enabled no)
			(sheetname "")
		)
		(fill
			(thermal_gap 0.5)
			(thermal_bridge_width 0.5)
			(island_removal_mode 0)
		)
		(polygon
			(pts
				(xy 30.13583 -131.661662) (xy 30.13583 -127.625602) (xy 34.01695 -127.625602) (xy 34.01695 -131.661662)
			)
		)
	)
	(zone
		(layer "F.Cu")
		(hatch none 0.5)
		(connect_pads
			(clearance 0)
		)
		(min_thickness 0.25)
		(keepout
			(tracks allowed)
			(vias allowed)
			(pads allowed)
			(copperpour allowed)
			(footprints allowed)
		)
		(placement
			(enabled no)
			(sheetname "")
		)
		(fill
			(thermal_gap 0.5)
			(thermal_bridge_width 0.5)
			(island_removal_mode 0)
		)
		(polygon
			(pts
				(xy 289.231578 -316.116462) (xy 289.231578 -315.672724) (xy 291.556694 -315.672724) (xy 291.556694 -316.116462)
			)
		)
	)
	(zone
		(layer "F.Cu")
		(hatch none 0.5)
		(connect_pads
			(clearance 0)
		)
		(min_thickness 0.25)
		(keepout
			(tracks allowed)
			(vias allowed)
			(pads allowed)
			(copperpour allowed)
			(footprints allowed)
		)
		(placement
			(enabled no)
			(sheetname "")
		)
		(fill
			(thermal_gap 0.5)
			(thermal_bridge_width 0.5)
			(island_removal_mode 0)
		)
		(polygon
			(pts
				(xy 96.989392 -335.958942) (xy 95.241872 -335.958942) (xy 95.241872 -334.023462) (xy 96.989392 -334.023462)
			)
		)
	)
	(zone
		(layer "F.Cu")
		(hatch none 0.5)
		(connect_pads
			(clearance 0)
		)
		(min_thickness 0.25)
		(keepout
			(tracks allowed)
			(vias allowed)
			(pads allowed)
			(copperpour allowed)
			(footprints allowed)
		)
		(placement
			(enabled no)
			(sheetname "")
		)
		(fill
			(thermal_gap 0.5)
			(thermal_bridge_width 0.5)
			(island_removal_mode 0)
		)
		(polygon
			(pts
				(xy 310.088026 -237.066582) (xy 307.76291 -237.066582) (xy 307.638958 -237.066582) (xy 307.638958 -235.864908)
				(xy 310.34482 -235.864908) (xy 310.34482 -237.066582)
			)
		)
	)
	(zone
		(layer "F.Cu")
		(hatch none 0.5)
		(connect_pads
			(clearance 0)
		)
		(min_thickness 0.25)
		(keepout
			(tracks allowed)
			(vias allowed)
			(pads allowed)
			(copperpour allowed)
			(footprints allowed)
		)
		(placement
			(enabled no)
			(sheetname "")
		)
		(fill
			(thermal_gap 0.5)
			(thermal_bridge_width 0.5)
			(island_removal_mode 0)
		)
		(polygon
			(pts
				(xy 29.647642 -315.266578) (xy 29.647642 -314.82284) (xy 31.972758 -314.82284) (xy 31.972758 -315.266578)
			)
		)
	)
	(zone
		(layer "F.Cu")
		(hatch none 0.5)
		(connect_pads
			(clearance 0)
		)
		(min_thickness 0.25)
		(keepout
			(tracks allowed)
			(vias allowed)
			(pads allowed)
			(copperpour allowed)
			(footprints allowed)
		)
		(placement
			(enabled no)
			(sheetname "")
		)
		(fill
			(thermal_gap 0.5)
			(thermal_bridge_width 0.5)
			(island_removal_mode 0)
		)
		(polygon
			(pts
				(xy 23.439882 -20.10791) (xy 23.439882 -16.973296) (xy 25.218644 -16.973296) (xy 25.218644 -20.10791)
			)
		)
	)
	(zone
		(layer "F.Cu")
		(hatch none 0.5)
		(connect_pads
			(clearance 0)
		)
		(min_thickness 0.25)
		(keepout
			(tracks allowed)
			(vias allowed)
			(pads allowed)
			(copperpour allowed)
			(footprints allowed)
		)
		(placement
			(enabled no)
			(sheetname "")
		)
		(fill
			(thermal_gap 0.5)
			(thermal_bridge_width 0.5)
			(island_removal_mode 0)
		)
		(polygon
			(pts
				(xy 161.891726 -205.504796) (xy 161.891726 -205.276196) (xy 163.923726 -205.276196) (xy 163.923726 -205.504796)
			)
		)
	)
	(zone
		(layer "F.Cu")
		(hatch none 0.5)
		(connect_pads
			(clearance 0)
		)
		(min_thickness 0.25)
		(keepout
			(tracks not_allowed)
			(vias allowed)
			(pads allowed)
			(copperpour not_allowed)
			(footprints allowed)
		)
		(placement
			(enabled no)
			(sheetname "")
		)
		(fill
			(thermal_gap 0.5)
			(thermal_bridge_width 0.5)
			(island_removal_mode 0)
		)
		(polygon
			(pts
				(xy 190.664084 -14.322552) (xy 190.839344 -14.322552) (xy 190.867284 -14.294612) (xy 190.867284 -12.900152)
				(xy 190.844424 -12.877292) (xy 190.674244 -12.877292) (xy 190.653924 -12.897612) (xy 190.653924 -14.312392)
			)
		)
	)
	(zone
		(layer "F.Cu")
		(hatch none 0.5)
		(connect_pads
			(clearance 0)
		)
		(min_thickness 0.25)
		(keepout
			(tracks allowed)
			(vias allowed)
			(pads allowed)
			(copperpour allowed)
			(footprints allowed)
		)
		(placement
			(enabled no)
			(sheetname "")
		)
		(fill
			(thermal_gap 0.5)
			(thermal_bridge_width 0.5)
			(island_removal_mode 0)
		)
		(polygon
			(pts
				(xy 424.919394 -303.876202) (xy 426.951394 -303.876202) (xy 426.951394 -304.104802) (xy 424.919394 -304.104802)
				(xy 424.788076 -304.104802) (xy 424.762168 -304.104802) (xy 424.762168 -303.876202) (xy 424.788076 -303.876202)
			)
		)
	)
	(zone
		(layer "F.Cu")
		(hatch none 0.5)
		(connect_pads
			(clearance 0)
		)
		(min_thickness 0.25)
		(keepout
			(tracks allowed)
			(vias allowed)
			(pads allowed)
			(copperpour allowed)
			(footprints allowed)
		)
		(placement
			(enabled no)
			(sheetname "")
		)
		(fill
			(thermal_gap 0.5)
			(thermal_bridge_width 0.5)
			(island_removal_mode 0)
		)
		(polygon
			(pts
				(xy 428.363126 -262.454898) (xy 428.363126 -262.226298) (xy 430.395126 -262.226298) (xy 430.395126 -262.454898)
			)
		)
	)
	(zone
		(layer "F.Cu")
		(hatch none 0.5)
		(connect_pads
			(clearance 0)
		)
		(min_thickness 0.25)
		(keepout
			(tracks allowed)
			(vias allowed)
			(pads allowed)
			(copperpour allowed)
			(footprints allowed)
		)
		(placement
			(enabled no)
			(sheetname "")
		)
		(fill
			(thermal_gap 0.5)
			(thermal_bridge_width 0.5)
			(island_removal_mode 0)
		)
		(polygon
			(pts
				(xy 277.58771 -271.472914) (xy 279.912826 -271.472914) (xy 279.981152 -271.472914) (xy 279.981152 -272.406618)
				(xy 277.460456 -272.406618) (xy 277.460456 -271.472914)
			)
		)
	)
	(zone
		(layer "F.Cu")
		(hatch none 0.5)
		(connect_pads
			(clearance 0)
		)
		(min_thickness 0.25)
		(keepout
			(tracks allowed)
			(vias allowed)
			(pads allowed)
			(copperpour allowed)
			(footprints allowed)
		)
		(placement
			(enabled no)
			(sheetname "")
		)
		(fill
			(thermal_gap 0.5)
			(thermal_bridge_width 0.5)
			(island_removal_mode 0)
		)
		(polygon
			(pts
				(xy 14.560042 -315.266578) (xy 14.560042 -314.82284) (xy 16.885158 -314.82284) (xy 16.885158 -315.266578)
			)
		)
	)
	(zone
		(layer "F.Cu")
		(hatch none 0.5)
		(connect_pads
			(clearance 0)
		)
		(min_thickness 0.25)
		(keepout
			(tracks allowed)
			(vias allowed)
			(pads allowed)
			(copperpour allowed)
			(footprints allowed)
		)
		(placement
			(enabled no)
			(sheetname "")
		)
		(fill
			(thermal_gap 0.5)
			(thermal_bridge_width 0.5)
			(island_removal_mode 0)
		)
		(polygon
			(pts
				(xy 397.957548 -20.04822) (xy 397.957548 -16.913606) (xy 399.73631 -16.913606) (xy 399.73631 -20.04822)
			)
		)
	)
	(zone
		(layer "F.Cu")
		(hatch none 0.5)
		(connect_pads
			(clearance 0)
		)
		(min_thickness 0.25)
		(keepout
			(tracks allowed)
			(vias allowed)
			(pads allowed)
			(copperpour allowed)
			(footprints allowed)
		)
		(placement
			(enabled no)
			(sheetname "")
		)
		(fill
			(thermal_gap 0.5)
			(thermal_bridge_width 0.5)
			(island_removal_mode 0)
		)
		(polygon
			(pts
				(xy 409.831794 -313.454796) (xy 409.831794 -313.226196) (xy 411.863794 -313.226196) (xy 411.863794 -313.454796)
			)
		)
	)
	(zone
		(layer "F.Cu")
		(hatch none 0.5)
		(connect_pads
			(clearance 0)
		)
		(min_thickness 0.25)
		(keepout
			(tracks allowed)
			(vias allowed)
			(pads allowed)
			(copperpour allowed)
			(footprints allowed)
		)
		(placement
			(enabled no)
			(sheetname "")
		)
		(fill
			(thermal_gap 0.5)
			(thermal_bridge_width 0.5)
			(island_removal_mode 0)
		)
		(polygon
			(pts
				(xy 445.11722 -13.292328) (xy 445.11722 -10.467848) (xy 447.39052 -10.467848) (xy 447.39052 -13.292328)
			)
		)
	)
	(zone
		(layer "F.Cu")
		(hatch none 0.5)
		(connect_pads
			(clearance 0)
		)
		(min_thickness 0.25)
		(keepout
			(tracks allowed)
			(vias allowed)
			(pads allowed)
			(copperpour allowed)
			(footprints allowed)
		)
		(placement
			(enabled no)
			(sheetname "")
		)
		(fill
			(thermal_gap 0.5)
			(thermal_bridge_width 0.5)
			(island_removal_mode 0)
		)
		(polygon
			(pts
				(xy 424.919394 -212.926422) (xy 426.951394 -212.926422) (xy 426.951394 -213.155022) (xy 424.919394 -213.155022)
				(xy 424.78325 -213.155022) (xy 424.73626 -213.155022) (xy 424.73626 -212.926422) (xy 424.78325 -212.926422)
			)
		)
	)
	(zone
		(layer "F.Cu")
		(hatch none 0.5)
		(connect_pads
			(clearance 0)
		)
		(min_thickness 0.25)
		(keepout
			(tracks allowed)
			(vias allowed)
			(pads allowed)
			(copperpour allowed)
			(footprints allowed)
		)
		(placement
			(enabled no)
			(sheetname "")
		)
		(fill
			(thermal_gap 0.5)
			(thermal_bridge_width 0.5)
			(island_removal_mode 0)
		)
		(polygon
			(pts
				(xy 55.70728 -155.593288) (xy 55.70728 -153.777188) (xy 57.0865 -153.777188) (xy 57.0865 -155.593288)
			)
		)
	)
	(zone
		(layer "F.Cu")
		(hatch none 0.5)
		(connect_pads
			(clearance 0)
		)
		(min_thickness 0.25)
		(keepout
			(tracks allowed)
			(vias allowed)
			(pads allowed)
			(copperpour allowed)
			(footprints not_allowed)
		)
		(placement
			(enabled no)
			(sheetname "")
		)
		(fill
			(thermal_gap 0.5)
			(thermal_bridge_width 0.5)
			(island_removal_mode 0)
		)
		(polygon
			(pts
				(xy 6.140704 -185.091832) (xy 6.140704 -331.091794) (xy 67.04711 -331.091794) (xy 67.04711 -185.091832)
			)
		)
	)
	(zone
		(layer "F.Cu")
		(hatch none 0.5)
		(connect_pads
			(clearance 0)
		)
		(min_thickness 0.25)
		(keepout
			(tracks allowed)
			(vias allowed)
			(pads allowed)
			(copperpour allowed)
			(footprints allowed)
		)
		(placement
			(enabled no)
			(sheetname "")
		)
		(fill
			(thermal_gap 0.5)
			(thermal_bridge_width 0.5)
			(island_removal_mode 0)
		)
		(polygon
			(pts
				(xy 41.29151 -268.922754) (xy 43.616626 -268.922754) (xy 43.69054 -268.922754) (xy 43.69054 -269.890748)
				(xy 41.157652 -269.890748) (xy 41.157652 -268.922754)
			)
		)
	)
	(zone
		(layer "F.Cu")
		(hatch none 0.5)
		(connect_pads
			(clearance 0)
		)
		(min_thickness 0.25)
		(keepout
			(tracks allowed)
			(vias allowed)
			(pads allowed)
			(copperpour allowed)
			(footprints allowed)
		)
		(placement
			(enabled no)
			(sheetname "")
		)
		(fill
			(thermal_gap 0.5)
			(thermal_bridge_width 0.5)
			(island_removal_mode 0)
		)
		(polygon
			(pts
				(xy 289.231578 -239.616488) (xy 289.231578 -239.17275) (xy 291.556694 -239.17275) (xy 291.556694 -239.616488)
			)
		)
	)
	(zone
		(layer "F.Cu")
		(hatch none 0.5)
		(connect_pads
			(clearance 0)
		)
		(min_thickness 0.25)
		(keepout
			(tracks allowed)
			(vias allowed)
			(pads allowed)
			(copperpour allowed)
			(footprints allowed)
		)
		(placement
			(enabled no)
			(sheetname "")
		)
		(fill
			(thermal_gap 0.5)
			(thermal_bridge_width 0.5)
			(island_removal_mode 0)
		)
		(polygon
			(pts
				(xy 289.231578 -231.966516) (xy 289.231578 -231.522778) (xy 291.556694 -231.522778) (xy 291.556694 -231.966516)
			)
		)
	)
	(zone
		(layer "F.Cu")
		(hatch none 0.5)
		(connect_pads
			(clearance 0)
		)
		(min_thickness 0.25)
		(keepout
			(tracks allowed)
			(vias allowed)
			(pads allowed)
			(copperpour allowed)
			(footprints allowed)
		)
		(placement
			(enabled no)
			(sheetname "")
		)
		(fill
			(thermal_gap 0.5)
			(thermal_bridge_width 0.5)
			(island_removal_mode 0)
		)
		(polygon
			(pts
				(xy 262.50011 -290.61664) (xy 262.50011 -290.172902) (xy 264.825226 -290.172902) (xy 264.825226 -290.61664)
			)
		)
	)
	(zone
		(layer "F.Cu")
		(hatch none 0.5)
		(connect_pads
			(clearance 0)
		)
		(min_thickness 0.25)
		(keepout
			(tracks not_allowed)
			(vias allowed)
			(pads allowed)
			(copperpour not_allowed)
			(footprints allowed)
		)
		(placement
			(enabled no)
			(sheetname "")
		)
		(fill
			(thermal_gap 0.5)
			(thermal_bridge_width 0.5)
			(island_removal_mode 0)
		)
		(polygon
			(pts
				(xy 415.923222 -163.13658) (xy 415.260282 -163.13658) (xy 415.260282 -164.68598) (xy 415.716974 -164.68598)
				(xy 415.716974 -163.990274) (xy 415.556446 -163.990274) (xy 415.556446 -163.431474) (xy 415.962846 -163.431474)
				(xy 415.962846 -163.990274) (xy 415.742374 -163.990274) (xy 415.742374 -164.68598) (xy 415.869374 -164.68598)
				(xy 415.869374 -164.230304) (xy 416.342322 -164.230304) (xy 416.342322 -163.987988) (xy 416.255962 -163.987988)
				(xy 416.255962 -163.38804) (xy 415.923222 -163.38804)
			)
		)
	)
	(zone
		(layer "F.Cu")
		(hatch none 0.5)
		(connect_pads
			(clearance 0)
		)
		(min_thickness 0.25)
		(keepout
			(tracks allowed)
			(vias allowed)
			(pads allowed)
			(copperpour allowed)
			(footprints allowed)
		)
		(placement
			(enabled no)
			(sheetname "")
		)
		(fill
			(thermal_gap 0.5)
			(thermal_bridge_width 0.5)
			(island_removal_mode 0)
		)
		(polygon
			(pts
				(xy 413.275526 -247.154954) (xy 413.275526 -246.926354) (xy 415.307526 -246.926354) (xy 415.307526 -247.154954)
			)
		)
	)
	(zone
		(layer "F.Cu")
		(hatch none 0.5)
		(connect_pads
			(clearance 0)
		)
		(min_thickness 0.25)
		(keepout
			(tracks allowed)
			(vias allowed)
			(pads allowed)
			(copperpour allowed)
			(footprints not_allowed)
		)
		(placement
			(enabled no)
			(sheetname "")
		)
		(fill
			(thermal_gap 0.5)
			(thermal_bridge_width 0.5)
			(island_removal_mode 0)
		)
		(polygon
			(pts
				(arc
					(start 6.621272 -407.40711)
					(mid 7.2717 -408.380405)
					(end 7.500112 -409.528518)
				)
				(arc
					(start 7.500112 -429.790606)
					(mid 18.60346 -429.89049)
					(end 18.91157 -440.989974)
				)
				(xy 54.200044 -440.989974) (xy 54.200044 -433.07) (xy 33.536636 -433.07) (xy 33.536636 -403.770084)
				(xy 34.536634 -403.770084) (xy 34.536634 -398.75587) (xy 2.999994 -398.75587)
				(arc
					(start 2.999994 -403.371558)
					(mid 3.076114 -403.754241)
					(end 3.292856 -404.078694)
				)
			)
		)
	)
	(zone
		(layer "F.Cu")
		(hatch none 0.5)
		(connect_pads
			(clearance 0)
		)
		(min_thickness 0.25)
		(keepout
			(tracks allowed)
			(vias allowed)
			(pads allowed)
			(copperpour allowed)
			(footprints allowed)
		)
		(placement
			(enabled no)
			(sheetname "")
		)
		(fill
			(thermal_gap 0.5)
			(thermal_bridge_width 0.5)
			(island_removal_mode 0)
		)
		(polygon
			(pts
				(xy 192.066926 -203.576428) (xy 194.098926 -203.576428) (xy 194.098926 -203.805028) (xy 192.066926 -203.805028)
				(xy 191.930782 -203.805028) (xy 191.883792 -203.805028) (xy 191.883792 -203.576428) (xy 191.930782 -203.576428)
			)
		)
	)
	(zone
		(layer "F.Cu")
		(hatch none 0.5)
		(connect_pads
			(clearance 0)
		)
		(min_thickness 0.25)
		(keepout
			(tracks allowed)
			(vias allowed)
			(pads allowed)
			(copperpour allowed)
			(footprints allowed)
		)
		(placement
			(enabled no)
			(sheetname "")
		)
		(fill
			(thermal_gap 0.5)
			(thermal_bridge_width 0.5)
			(island_removal_mode 0)
		)
		(polygon
			(pts
				(xy 314.188094 -276.16658) (xy 311.81548 -276.16658) (xy 311.75579 -276.16658) (xy 311.75579 -274.923504)
				(xy 314.248292 -274.923504) (xy 314.248292 -276.16658)
			)
		)
	)
	(zone
		(layer "F.Cu")
		(hatch none 0.5)
		(connect_pads
			(clearance 0)
		)
		(min_thickness 0.25)
		(keepout
			(tracks allowed)
			(vias allowed)
			(pads allowed)
			(copperpour allowed)
			(footprints allowed)
		)
		(placement
			(enabled no)
			(sheetname "")
		)
		(fill
			(thermal_gap 0.5)
			(thermal_bridge_width 0.5)
			(island_removal_mode 0)
		)
		(polygon
			(pts
				(xy 389.345424 -404.802594) (xy 389.345424 -399.959576) (xy 391.22985 -399.959576) (xy 391.22985 -404.802594)
			)
		)
	)
	(zone
		(layer "F.Cu")
		(hatch none 0.5)
		(connect_pads
			(clearance 0)
		)
		(min_thickness 0.25)
		(keepout
			(tracks allowed)
			(vias allowed)
			(pads allowed)
			(copperpour allowed)
			(footprints allowed)
		)
		(placement
			(enabled no)
			(sheetname "")
		)
		(fill
			(thermal_gap 0.5)
			(thermal_bridge_width 0.5)
			(island_removal_mode 0)
		)
		(polygon
			(pts
				(xy 125.66904 -342.684608) (xy 125.66904 -337.612228) (xy 131.80314 -337.612228) (xy 131.80314 -342.684608)
			)
		)
	)
	(zone
		(layer "F.Cu")
		(hatch none 0.5)
		(connect_pads
			(clearance 0)
		)
		(min_thickness 0.25)
		(keepout
			(tracks allowed)
			(vias allowed)
			(pads allowed)
			(copperpour allowed)
			(footprints allowed)
		)
		(placement
			(enabled no)
			(sheetname "")
		)
		(fill
			(thermal_gap 0.5)
			(thermal_bridge_width 0.5)
			(island_removal_mode 0)
		)
		(polygon
			(pts
				(xy 135.56996 -289.037268) (xy 135.85698 -289.037268) (xy 135.88746 -289.006788) (xy 135.88746 -288.379408)
				(xy 135.8011 -288.293048) (xy 135.61314 -288.293048) (xy 135.53948 -288.366708) (xy 135.53948 -289.006788)
			)
		)
	)
	(zone
		(layer "F.Cu")
		(hatch none 0.5)
		(connect_pads
			(clearance 0)
		)
		(min_thickness 0.25)
		(keepout
			(tracks allowed)
			(vias allowed)
			(pads allowed)
			(copperpour allowed)
			(footprints allowed)
		)
		(placement
			(enabled no)
			(sheetname "")
		)
		(fill
			(thermal_gap 0.5)
			(thermal_bridge_width 0.5)
			(island_removal_mode 0)
		)
		(polygon
			(pts
				(xy 21.58746 -160.089088) (xy 21.58746 -159.012128) (xy 23.241 -159.012128) (xy 23.241 -160.089088)
			)
		)
	)
	(zone
		(layer "F.Cu")
		(hatch none 0.5)
		(connect_pads
			(clearance 0)
		)
		(min_thickness 0.25)
		(keepout
			(tracks allowed)
			(vias allowed)
			(pads allowed)
			(copperpour allowed)
			(footprints allowed)
		)
		(placement
			(enabled no)
			(sheetname "")
		)
		(fill
			(thermal_gap 0.5)
			(thermal_bridge_width 0.5)
			(island_removal_mode 0)
		)
		(polygon
			(pts
				(xy 458.538326 -282.005024) (xy 458.538326 -281.776424) (xy 460.570326 -281.776424) (xy 460.570326 -282.005024)
			)
		)
	)
	(zone
		(layer "F.Cu")
		(hatch none 0.5)
		(connect_pads
			(clearance 0)
		)
		(min_thickness 0.25)
		(keepout
			(tracks allowed)
			(vias allowed)
			(pads allowed)
			(copperpour allowed)
			(footprints allowed)
		)
		(placement
			(enabled no)
			(sheetname "")
		)
		(fill
			(thermal_gap 0.5)
			(thermal_bridge_width 0.5)
			(island_removal_mode 0)
		)
		(polygon
			(pts
				(xy 405.731726 -208.054956) (xy 405.731726 -207.826356) (xy 407.763726 -207.826356) (xy 407.763726 -208.054956)
			)
		)
	)
	(zone
		(layer "F.Cu")
		(hatch none 0.5)
		(connect_pads
			(clearance 0)
		)
		(min_thickness 0.25)
		(keepout
			(tracks allowed)
			(vias allowed)
			(pads allowed)
			(copperpour allowed)
			(footprints allowed)
		)
		(placement
			(enabled no)
			(sheetname "")
		)
		(fill
			(thermal_gap 0.5)
			(thermal_bridge_width 0.5)
			(island_removal_mode 0)
		)
		(polygon
			(pts
				(xy 369.410742 -335.958942) (xy 367.663222 -335.958942) (xy 367.663222 -334.023462) (xy 369.410742 -334.023462)
			)
		)
	)
	(zone
		(layer "F.Cu")
		(hatch none 0.5)
		(connect_pads
			(clearance 0)
		)
		(min_thickness 0.25)
		(keepout
			(tracks allowed)
			(vias allowed)
			(pads allowed)
			(copperpour allowed)
			(footprints allowed)
		)
		(placement
			(enabled no)
			(sheetname "")
		)
		(fill
			(thermal_gap 0.5)
			(thermal_bridge_width 0.5)
			(island_removal_mode 0)
		)
		(polygon
			(pts
				(xy 377.092464 -404.802594) (xy 377.092464 -399.959576) (xy 378.97689 -399.959576) (xy 378.97689 -404.802594)
			)
		)
	)
	(zone
		(layer "F.Cu")
		(hatch none 0.5)
		(connect_pads
			(clearance 0)
		)
		(min_thickness 0.25)
		(keepout
			(tracks allowed)
			(vias allowed)
			(pads allowed)
			(copperpour allowed)
			(footprints allowed)
		)
		(placement
			(enabled no)
			(sheetname "")
		)
		(fill
			(thermal_gap 0.5)
			(thermal_bridge_width 0.5)
			(island_removal_mode 0)
		)
		(polygon
			(pts
				(xy 415.201862 -171.70654) (xy 415.201862 -173.52264) (xy 413.822642 -173.52264) (xy 413.822642 -171.70654)
			)
		)
	)
	(zone
		(layer "F.Cu")
		(hatch none 0.5)
		(connect_pads
			(clearance 0)
		)
		(min_thickness 0.25)
		(keepout
			(tracks allowed)
			(vias allowed)
			(pads allowed)
			(copperpour allowed)
			(footprints allowed)
		)
		(placement
			(enabled no)
			(sheetname "")
		)
		(fill
			(thermal_gap 0.5)
			(thermal_bridge_width 0.5)
			(island_removal_mode 0)
		)
		(polygon
			(pts
				(xy 157.791658 -310.90489) (xy 157.791658 -310.67629) (xy 159.823658 -310.67629) (xy 159.823658 -310.90489)
			)
		)
	)
	(zone
		(layer "F.Cu")
		(hatch none 0.5)
		(connect_pads
			(clearance 0)
		)
		(min_thickness 0.25)
		(keepout
			(tracks allowed)
			(vias allowed)
			(pads allowed)
			(copperpour allowed)
			(footprints allowed)
		)
		(placement
			(enabled no)
			(sheetname "")
		)
		(fill
			(thermal_gap 0.5)
			(thermal_bridge_width 0.5)
			(island_removal_mode 0)
		)
		(polygon
			(pts
				(xy 386.373116 -275.383752) (xy 386.576062 -275.586698) (xy 386.618988 -275.586698) (xy 387.062726 -275.143214)
				(xy 387.062726 -275.02104) (xy 386.929884 -274.887944) (xy 386.825744 -274.887944) (xy 386.373116 -275.340572)
			)
		)
	)
	(zone
		(layer "F.Cu")
		(hatch none 0.5)
		(connect_pads
			(clearance 0)
		)
		(min_thickness 0.25)
		(keepout
			(tracks allowed)
			(vias allowed)
			(pads allowed)
			(copperpour allowed)
			(footprints allowed)
		)
		(placement
			(enabled no)
			(sheetname "")
		)
		(fill
			(thermal_gap 0.5)
			(thermal_bridge_width 0.5)
			(island_removal_mode 0)
		)
		(polygon
			(pts
				(xy 413.275526 -264.15492) (xy 413.275526 -263.92632) (xy 415.307526 -263.92632) (xy 415.307526 -264.15492)
			)
		)
	)
	(zone
		(layer "F.Cu")
		(hatch none 0.5)
		(connect_pads
			(clearance 0)
		)
		(min_thickness 0.25)
		(keepout
			(tracks allowed)
			(vias allowed)
			(pads allowed)
			(copperpour allowed)
			(footprints allowed)
		)
		(placement
			(enabled no)
			(sheetname "")
		)
		(fill
			(thermal_gap 0.5)
			(thermal_bridge_width 0.5)
			(island_removal_mode 0)
		)
		(polygon
			(pts
				(xy 292.67531 -221.766638) (xy 292.67531 -221.3229) (xy 295.000426 -221.3229) (xy 295.000426 -221.766638)
			)
		)
	)
	(zone
		(layer "F.Cu")
		(hatch none 0.5)
		(connect_pads
			(clearance 0)
		)
		(min_thickness 0.25)
		(keepout
			(tracks allowed)
			(vias allowed)
			(pads allowed)
			(copperpour allowed)
			(footprints allowed)
		)
		(placement
			(enabled no)
			(sheetname "")
		)
		(fill
			(thermal_gap 0.5)
			(thermal_bridge_width 0.5)
			(island_removal_mode 0)
		)
		(polygon
			(pts
				(xy 455.094594 -280.076402) (xy 457.126594 -280.076402) (xy 457.126594 -280.305002) (xy 455.094594 -280.305002)
				(xy 454.95845 -280.305002) (xy 454.91146 -280.305002) (xy 454.91146 -280.076402) (xy 454.95845 -280.076402)
			)
		)
	)
	(zone
		(layer "F.Cu")
		(hatch none 0.5)
		(connect_pads
			(clearance 0)
		)
		(min_thickness 0.25)
		(keepout
			(tracks allowed)
			(vias allowed)
			(pads allowed)
			(copperpour allowed)
			(footprints allowed)
		)
		(placement
			(enabled no)
			(sheetname "")
		)
		(fill
			(thermal_gap 0.5)
			(thermal_bridge_width 0.5)
			(island_removal_mode 0)
		)
		(polygon
			(pts
				(xy 11.11631 -265.966448) (xy 11.11631 -265.52271) (xy 13.441426 -265.52271) (xy 13.441426 -265.966448)
			)
		)
	)
	(zone
		(layer "F.Cu")
		(hatch none 0.5)
		(connect_pads
			(clearance 0)
		)
		(min_thickness 0.25)
		(keepout
			(tracks allowed)
			(vias allowed)
			(pads allowed)
			(copperpour allowed)
			(footprints allowed)
		)
		(placement
			(enabled no)
			(sheetname "")
		)
		(fill
			(thermal_gap 0.5)
			(thermal_bridge_width 0.5)
			(island_removal_mode 0)
		)
		(polygon
			(pts
				(xy 14.560042 -205.616556) (xy 14.560042 -205.172818) (xy 16.885158 -205.172818) (xy 16.885158 -205.616556)
			)
		)
	)
	(zone
		(layer "F.Cu")
		(hatch none 0.5)
		(connect_pads
			(clearance 0)
		)
		(min_thickness 0.25)
		(keepout
			(tracks not_allowed)
			(vias allowed)
			(pads allowed)
			(copperpour not_allowed)
			(footprints allowed)
		)
		(placement
			(enabled no)
			(sheetname "")
		)
		(fill
			(thermal_gap 0.5)
			(thermal_bridge_width 0.5)
			(island_removal_mode 0)
		)
		(polygon
			(pts
				(arc
					(start 368.498628 -435.600094)
					(mid 371.298724 -432.799998)
					(end 374.098566 -435.600094)
				)
				(arc
					(start 374.098566 -435.600094)
					(mid 371.298724 -438.399936)
					(end 368.498628 -435.600094)
				)
			)
		)
	)
	(zone
		(layer "F.Cu")
		(hatch none 0.5)
		(connect_pads
			(clearance 0)
		)
		(min_thickness 0.25)
		(keepout
			(tracks allowed)
			(vias allowed)
			(pads allowed)
			(copperpour allowed)
			(footprints not_allowed)
		)
		(placement
			(enabled no)
			(sheetname "")
		)
		(fill
			(thermal_gap 0.5)
			(thermal_bridge_width 0.5)
			(island_removal_mode 0)
		)
		(polygon
			(pts
				(arc
					(start 98.1329 -47.049944)
					(mid 100.383086 -44.799758)
					(end 102.633018 -47.049944)
				)
				(arc
					(start 102.633018 -47.049944)
					(mid 100.383086 -49.299876)
					(end 98.1329 -47.049944)
				)
			)
		)
	)
	(zone
		(layer "F.Cu")
		(hatch none 0.5)
		(connect_pads
			(clearance 0)
		)
		(min_thickness 0.25)
		(keepout
			(tracks allowed)
			(vias allowed)
			(pads allowed)
			(copperpour allowed)
			(footprints not_allowed)
		)
		(placement
			(enabled no)
			(sheetname "")
		)
		(fill
			(thermal_gap 0.5)
			(thermal_bridge_width 0.5)
			(island_removal_mode 0)
		)
		(polygon
			(pts
				(arc
					(start 240.89995 -81.700116)
					(mid 235.89996 -86.700106)
					(end 230.89997 -81.700116)
				)
				(arc
					(start 230.89997 -81.700116)
					(mid 235.89996 -76.700126)
					(end 240.89995 -81.700116)
				)
			)
		)
	)
	(zone
		(layer "F.Cu")
		(hatch none 0.5)
		(connect_pads
			(clearance 0)
		)
		(min_thickness 0.25)
		(keepout
			(tracks allowed)
			(vias allowed)
			(pads allowed)
			(copperpour allowed)
			(footprints allowed)
		)
		(placement
			(enabled no)
			(sheetname "")
		)
		(fill
			(thermal_gap 0.5)
			(thermal_bridge_width 0.5)
			(island_removal_mode 0)
		)
		(polygon
			(pts
				(xy 424.919394 -201.026268) (xy 426.951394 -201.026268) (xy 426.951394 -201.254868) (xy 424.919394 -201.254868)
				(xy 424.788076 -201.254868) (xy 424.762168 -201.254868) (xy 424.762168 -201.026268) (xy 424.788076 -201.026268)
			)
		)
	)
	(zone
		(layer "F.Cu")
		(hatch none 0.5)
		(connect_pads
			(clearance 0)
		)
		(min_thickness 0.25)
		(keepout
			(tracks allowed)
			(vias allowed)
			(pads allowed)
			(copperpour allowed)
			(footprints allowed)
		)
		(placement
			(enabled no)
			(sheetname "")
		)
		(fill
			(thermal_gap 0.5)
			(thermal_bridge_width 0.5)
			(island_removal_mode 0)
		)
		(polygon
			(pts
				(xy 44.735242 -202.216512) (xy 44.735242 -201.772774) (xy 47.060358 -201.772774) (xy 47.060358 -202.216512)
			)
		)
	)
	(zone
		(layer "F.Cu")
		(hatch none 0.5)
		(connect_pads
			(clearance 0)
		)
		(min_thickness 0.25)
		(keepout
			(tracks allowed)
			(vias allowed)
			(pads allowed)
			(copperpour allowed)
			(footprints allowed)
		)
		(placement
			(enabled no)
			(sheetname "")
		)
		(fill
			(thermal_gap 0.5)
			(thermal_bridge_width 0.5)
			(island_removal_mode 0)
		)
		(polygon
			(pts
				(xy 180.423058 -278.60498) (xy 180.423058 -278.37638) (xy 182.455058 -278.37638) (xy 182.455058 -278.60498)
			)
		)
	)
	(zone
		(layer "F.Cu")
		(hatch none 0.5)
		(connect_pads
			(clearance 0)
		)
		(min_thickness 0.25)
		(keepout
			(tracks not_allowed)
			(vias allowed)
			(pads allowed)
			(copperpour not_allowed)
			(footprints allowed)
		)
		(placement
			(enabled no)
			(sheetname "")
		)
		(fill
			(thermal_gap 0.5)
			(thermal_bridge_width 0.5)
			(island_removal_mode 0)
		)
		(polygon
			(pts
				(xy 64.86906 -11.992356) (xy 65.04432 -11.992356) (xy 65.07226 -11.964416) (xy 65.07226 -10.569956)
				(xy 65.0494 -10.547096) (xy 64.87922 -10.547096) (xy 64.8589 -10.567416) (xy 64.8589 -11.982196)
			)
		)
	)
	(zone
		(layer "F.Cu")
		(hatch none 0.5)
		(connect_pads
			(clearance 0)
		)
		(min_thickness 0.25)
		(keepout
			(tracks allowed)
			(vias allowed)
			(pads allowed)
			(copperpour allowed)
			(footprints allowed)
		)
		(placement
			(enabled no)
			(sheetname "")
		)
		(fill
			(thermal_gap 0.5)
			(thermal_bridge_width 0.5)
			(island_removal_mode 0)
		)
		(polygon
			(pts
				(xy 176.979326 -220.576394) (xy 179.011326 -220.576394) (xy 179.011326 -220.804994) (xy 176.979326 -220.804994)
				(xy 176.843182 -220.804994) (xy 176.796192 -220.804994) (xy 176.796192 -220.576394) (xy 176.843182 -220.576394)
			)
		)
	)
	(zone
		(layer "F.Cu")
		(hatch none 0.5)
		(connect_pads
			(clearance 0)
		)
		(min_thickness 0.25)
		(keepout
			(tracks allowed)
			(vias allowed)
			(pads allowed)
			(copperpour allowed)
			(footprints allowed)
		)
		(placement
			(enabled no)
			(sheetname "")
		)
		(fill
			(thermal_gap 0.5)
			(thermal_bridge_width 0.5)
			(island_removal_mode 0)
		)
		(polygon
			(pts
				(xy 335.08188 -288.206688) (xy 335.3689 -288.206688) (xy 335.39938 -288.176208) (xy 335.39938 -287.548828)
				(xy 335.31302 -287.462468) (xy 335.12506 -287.462468) (xy 335.0514 -287.536128) (xy 335.0514 -288.176208)
			)
		)
	)
	(zone
		(layer "F.Cu")
		(hatch none 0.5)
		(connect_pads
			(clearance 0)
		)
		(min_thickness 0.25)
		(keepout
			(tracks allowed)
			(vias allowed)
			(pads allowed)
			(copperpour allowed)
			(footprints not_allowed)
		)
		(placement
			(enabled no)
			(sheetname "")
		)
		(fill
			(thermal_gap 0.5)
			(thermal_bridge_width 0.5)
			(island_removal_mode 0)
		)
		(polygon
			(pts
				(xy 172.901102 -330.091796) (xy 179.000912 -330.091796) (xy 179.000912 -186.09183) (xy 172.901102 -186.09183)
			)
		)
	)
	(zone
		(layer "F.Cu")
		(hatch none 0.5)
		(connect_pads
			(clearance 0)
		)
		(min_thickness 0.25)
		(keepout
			(tracks allowed)
			(vias allowed)
			(pads allowed)
			(copperpour allowed)
			(footprints allowed)
		)
		(placement
			(enabled no)
			(sheetname "")
		)
		(fill
			(thermal_gap 0.5)
			(thermal_bridge_width 0.5)
			(island_removal_mode 0)
		)
		(polygon
			(pts
				(xy 29.647642 -268.516354) (xy 29.647642 -268.072616) (xy 29.647642 -267.659358) (xy 29.711142 -267.595858)
				(xy 32.00654 -267.595858) (xy 32.139382 -267.7287) (xy 32.139382 -268.467332) (xy 32.09036 -268.516354)
				(xy 31.972758 -268.516354)
			)
		)
	)
	(zone
		(layer "F.Cu")
		(hatch none 0.5)
		(connect_pads
			(clearance 0)
		)
		(min_thickness 0.25)
		(keepout
			(tracks allowed)
			(vias allowed)
			(pads allowed)
			(copperpour allowed)
			(footprints allowed)
		)
		(placement
			(enabled no)
			(sheetname "")
		)
		(fill
			(thermal_gap 0.5)
			(thermal_bridge_width 0.5)
			(island_removal_mode 0)
		)
		(polygon
			(pts
				(xy 274.143978 -314.41644) (xy 274.143978 -313.972702) (xy 276.469094 -313.972702) (xy 276.469094 -314.41644)
			)
		)
	)
	(zone
		(layer "F.Cu")
		(hatch none 0.5)
		(connect_pads
			(clearance 0)
		)
		(min_thickness 0.25)
		(keepout
			(tracks allowed)
			(vias allowed)
			(pads allowed)
			(copperpour allowed)
			(footprints allowed)
		)
		(placement
			(enabled no)
			(sheetname "")
		)
		(fill
			(thermal_gap 0.5)
			(thermal_bridge_width 0.5)
			(island_removal_mode 0)
		)
		(polygon
			(pts
				(xy 296.624756 -319.243456) (xy 296.624756 -316.881256) (xy 299.240956 -316.881256) (xy 299.240956 -319.243456)
			)
		)
	)
	(zone
		(layer "F.Cu")
		(hatch none 0.5)
		(connect_pads
			(clearance 0)
		)
		(min_thickness 0.25)
		(keepout
			(tracks not_allowed)
			(vias allowed)
			(pads allowed)
			(copperpour not_allowed)
			(footprints allowed)
		)
		(placement
			(enabled no)
			(sheetname "")
		)
		(fill
			(thermal_gap 0.5)
			(thermal_bridge_width 0.5)
			(island_removal_mode 0)
		)
		(polygon
			(pts
				(arc
					(start 290.079938 -419.999922)
					(mid 287.98012 -422.09974)
					(end 285.880048 -419.999922)
				)
				(arc
					(start 285.880048 -419.999922)
					(mid 287.98012 -417.89985)
					(end 290.079938 -419.999922)
				)
			)
		)
	)
	(zone
		(layer "F.Cu")
		(hatch none 0.5)
		(connect_pads
			(clearance 0)
		)
		(min_thickness 0.25)
		(keepout
			(tracks allowed)
			(vias allowed)
			(pads allowed)
			(copperpour allowed)
			(footprints allowed)
		)
		(placement
			(enabled no)
			(sheetname "")
		)
		(fill
			(thermal_gap 0.5)
			(thermal_bridge_width 0.5)
			(island_removal_mode 0)
		)
		(polygon
			(pts
				(xy 405.731726 -282.854908) (xy 405.731726 -282.626308) (xy 407.763726 -282.626308) (xy 407.763726 -282.854908)
			)
		)
	)
	(zone
		(layer "F.Cu")
		(hatch none 0.5)
		(connect_pads
			(clearance 0)
		)
		(min_thickness 0.25)
		(keepout
			(tracks allowed)
			(vias allowed)
			(pads allowed)
			(copperpour allowed)
			(footprints allowed)
		)
		(placement
			(enabled no)
			(sheetname "")
		)
		(fill
			(thermal_gap 0.5)
			(thermal_bridge_width 0.5)
			(island_removal_mode 0)
		)
		(polygon
			(pts
				(xy 161.891726 -313.454796) (xy 161.891726 -313.226196) (xy 163.923726 -313.226196) (xy 163.923726 -313.454796)
			)
		)
	)
	(zone
		(layer "F.Cu")
		(hatch none 0.5)
		(connect_pads
			(clearance 0)
		)
		(min_thickness 0.25)
		(keepout
			(tracks allowed)
			(vias allowed)
			(pads allowed)
			(copperpour allowed)
			(footprints allowed)
		)
		(placement
			(enabled no)
			(sheetname "")
		)
		(fill
			(thermal_gap 0.5)
			(thermal_bridge_width 0.5)
			(island_removal_mode 0)
		)
		(polygon
			(pts
				(xy 304.319178 -305.066446) (xy 304.319178 -304.622708) (xy 306.644294 -304.622708) (xy 306.644294 -305.066446)
			)
		)
	)
	(zone
		(layer "F.Cu")
		(hatch none 0.5)
		(connect_pads
			(clearance 0)
		)
		(min_thickness 0.25)
		(keepout
			(tracks allowed)
			(vias allowed)
			(pads allowed)
			(copperpour allowed)
			(footprints allowed)
		)
		(placement
			(enabled no)
			(sheetname "")
		)
		(fill
			(thermal_gap 0.5)
			(thermal_bridge_width 0.5)
			(island_removal_mode 0)
		)
		(polygon
			(pts
				(xy 26.20391 -312.716418) (xy 26.20391 -312.27268) (xy 28.529026 -312.27268) (xy 28.529026 -312.716418)
			)
		)
	)
	(zone
		(layer "F.Cu")
		(hatch none 0.5)
		(connect_pads
			(clearance 0)
		)
		(min_thickness 0.25)
		(keepout
			(tracks allowed)
			(vias allowed)
			(pads allowed)
			(copperpour allowed)
			(footprints allowed)
		)
		(placement
			(enabled no)
			(sheetname "")
		)
		(fill
			(thermal_gap 0.5)
			(thermal_bridge_width 0.5)
			(island_removal_mode 0)
		)
		(polygon
			(pts
				(xy 161.891726 -285.404814) (xy 161.891726 -285.176214) (xy 163.923726 -285.176214) (xy 163.923726 -285.404814)
			)
		)
	)
	(zone
		(layer "F.Cu")
		(hatch none 0.5)
		(connect_pads
			(clearance 0)
		)
		(min_thickness 0.25)
		(keepout
			(tracks allowed)
			(vias allowed)
			(pads allowed)
			(copperpour allowed)
			(footprints allowed)
		)
		(placement
			(enabled no)
			(sheetname "")
		)
		(fill
			(thermal_gap 0.5)
			(thermal_bridge_width 0.5)
			(island_removal_mode 0)
		)
		(polygon
			(pts
				(xy 69.82714 -13.218668) (xy 69.82714 -9.972548) (xy 73.58634 -9.972548) (xy 73.58634 -13.218668)
			)
		)
	)
	(zone
		(layer "F.Cu")
		(hatch none 0.5)
		(connect_pads
			(clearance 0)
		)
		(min_thickness 0.25)
		(keepout
			(tracks allowed)
			(vias allowed)
			(pads allowed)
			(copperpour allowed)
			(footprints allowed)
		)
		(placement
			(enabled no)
			(sheetname "")
		)
		(fill
			(thermal_gap 0.5)
			(thermal_bridge_width 0.5)
			(island_removal_mode 0)
		)
		(polygon
			(pts
				(xy 11.11631 -299.116496) (xy 11.11631 -298.672758) (xy 13.441426 -298.672758) (xy 13.441426 -299.116496)
			)
		)
	)
	(zone
		(layer "F.Cu")
		(hatch none 0.5)
		(connect_pads
			(clearance 0)
		)
		(min_thickness 0.25)
		(keepout
			(tracks allowed)
			(vias allowed)
			(pads allowed)
			(copperpour allowed)
			(footprints allowed)
		)
		(placement
			(enabled no)
			(sheetname "")
		)
		(fill
			(thermal_gap 0.5)
			(thermal_bridge_width 0.5)
			(island_removal_mode 0)
		)
		(polygon
			(pts
				(xy 44.735242 -199.666606) (xy 44.735242 -199.222868) (xy 47.060358 -199.222868) (xy 47.060358 -199.666606)
			)
		)
	)
	(zone
		(layer "F.Cu")
		(hatch none 0.5)
		(connect_pads
			(clearance 0)
		)
		(min_thickness 0.25)
		(keepout
			(tracks allowed)
			(vias allowed)
			(pads allowed)
			(copperpour allowed)
			(footprints allowed)
		)
		(placement
			(enabled no)
			(sheetname "")
		)
		(fill
			(thermal_gap 0.5)
			(thermal_bridge_width 0.5)
			(island_removal_mode 0)
		)
		(polygon
			(pts
				(xy 304.319178 -300.816518) (xy 304.319178 -300.37278) (xy 306.644294 -300.37278) (xy 306.644294 -300.816518)
			)
		)
	)
	(zone
		(layer "F.Cu")
		(hatch none 0.5)
		(connect_pads
			(clearance 0)
		)
		(min_thickness 0.25)
		(keepout
			(tracks allowed)
			(vias allowed)
			(pads allowed)
			(copperpour allowed)
			(footprints allowed)
		)
		(placement
			(enabled no)
			(sheetname "")
		)
		(fill
			(thermal_gap 0.5)
			(thermal_bridge_width 0.5)
			(island_removal_mode 0)
		)
		(polygon
			(pts
				(xy 84.893912 -300.520862) (xy 85.032342 -300.520862) (xy 85.032088 -286.63265) (xy 85.101938 -286.5628)
				(xy 85.101938 -282.06192) (xy 85.635338 -281.52852) (xy 85.635338 -280.15565) (xy 85.621876 -280.142188)
				(xy 85.533992 -280.142188) (xy 85.346286 -279.954482) (xy 85.346286 -279.8826) (xy 85.229446 -279.76576)
				(xy 84.954364 -279.76576) (xy 84.894166 -279.825958) (xy 84.723732 -279.825958) (xy 84.598256 -279.700482)
				(xy 84.567522 -279.700482) (xy 84.471764 -279.700482) (xy 84.065364 -279.294082) (xy 84.065364 -279.199848)
				(xy 84.243164 -279.022302) (xy 84.243164 -278.940768) (xy 83.89239 -278.589994) (xy 83.82889 -278.589994)
				(xy 83.65617 -278.762714) (xy 83.565492 -278.762714) (xy 82.58556 -277.782782) (xy 82.58556 -277.664164)
				(xy 84.650072 -275.599652) (xy 84.650072 -275.500338) (xy 83.787234 -274.6375) (xy 83.625182 -274.6375)
				(xy 83.246722 -274.25904) (xy 83.246722 -274.15871) (xy 83.46694 -273.938492) (xy 83.46694 -273.872198)
				(xy 83.14563 -273.550888) (xy 83.14563 -273.444716) (xy 83.2993 -273.291046) (xy 83.2993 -273.228816)
				(xy 83.102958 -273.032474) (xy 83.102958 -272.964148) (xy 84.327746 -271.73936) (xy 84.327746 -271.72158)
				(xy 84.176108 -271.569942) (xy 84.176108 -271.498314) (xy 84.624164 -271.050258) (xy 84.624164 -271.010634)
				(xy 84.205826 -270.592296) (xy 84.205826 -270.218662) (xy 83.593686 -269.606522) (xy 83.593686 -269.52067)
				(xy 83.951064 -269.163292) (xy 83.951064 -269.129764) (xy 83.79841 -268.97711) (xy 83.772248 -268.97711)
				(xy 83.222084 -269.527274) (xy 83.123024 -269.527274) (xy 82.753962 -269.158212) (xy 82.753962 -269.047468)
				(xy 83.388708 -268.412722) (xy 83.388708 -268.353286) (xy 83.02371 -267.988288) (xy 83.02371 -267.885164)
				(xy 83.331304 -267.57757) (xy 83.331304 -267.519912) (xy 83.172554 -267.361162) (xy 83.172554 -267.327888)
				(xy 83.247992 -267.25245) (xy 83.717892 -266.78255) (xy 83.989418 -266.511024) (xy 83.989418 -265.94181)
				(xy 83.773518 -265.72591) (xy 83.773518 -264.791952) (xy 83.696048 -264.714482) (xy 82.771996 -264.714482)
				(xy 82.533998 -264.476484) (xy 82.533998 -264.311892) (xy 82.601308 -264.244582) (xy 82.601308 -264.188702)
				(xy 82.45475 -264.042144) (xy 82.45475 -263.958832) (xy 82.551778 -263.861804) (xy 82.551778 -263.786366)
				(xy 82.414872 -263.64946) (xy 82.414872 -263.56437) (xy 82.557874 -263.421368) (xy 83.705954 -263.421368)
				(xy 83.745578 -263.381744) (xy 83.745578 -263.220962) (xy 83.703922 -263.179306) (xy 82.704432 -263.179306)
				(xy 82.609182 -263.084056) (xy 82.609182 -262.471662) (xy 82.700368 -262.380476) (xy 82.92846 -262.380476)
				(xy 82.9564 -262.352536) (xy 82.9564 -261.914132) (xy 82.916776 -261.874508) (xy 82.654902 -261.874508)
				(xy 82.599276 -261.818882) (xy 82.599276 -261.430262) (xy 82.67446 -261.355078) (xy 83.710018 -261.355078)
				(xy 83.733894 -261.378954) (xy 83.818984 -261.378954) (xy 83.932014 -261.265924) (xy 83.932014 -261.204456)
				(xy 83.850734 -261.123176) (xy 83.339178 -261.123176) (xy 83.279742 -261.06374) (xy 83.279742 -260.02234)
				(xy 83.374992 -259.92709) (xy 83.500214 -259.92709) (xy 83.678522 -259.748782) (xy 83.678522 -259.562092)
				(xy 83.736942 -259.503672) (xy 83.736942 -258.836922) (xy 83.626452 -258.726432) (xy 83.626452 -258.539234)
				(xy 83.665822 -258.499864) (xy 83.665822 -258.485132) (xy 83.665568 -258.485132) (xy 83.53933 -258.358894)
				(xy 83.53933 -258.315206) (xy 83.57489 -258.279646) (xy 83.57489 -258.142486) (xy 83.483704 -258.0513)
				(xy 83.483704 -257.991102) (xy 83.553046 -257.92176) (xy 83.619086 -257.85572) (xy 83.796886 -257.67792)
				(xy 85.026754 -257.67792) (xy 85.12175 -257.582924) (xy 85.12175 -257.394964) (xy 84.979002 -257.252216)
				(xy 84.674456 -257.252216) (xy 84.589366 -257.167126) (xy 84.589366 -257.02006) (xy 84.569808 -257.000502)
				(xy 84.307172 -257.000502) (xy 84.18576 -256.87909) (xy 84.18576 -256.336038) (xy 82.791808 -254.942086)
				(xy 82.791808 -254.746252) (xy 81.447386 -256.090674) (xy 74.179938 -256.090674) (xy 74.121518 -256.090674)
				(xy 74.121518 -256.417572) (xy 73.804018 -256.735072) (xy 73.804018 -257.108452) (xy 73.897998 -257.202432)
				(xy 74.383138 -257.202432) (xy 74.573638 -257.392932) (xy 74.827638 -257.392932) (xy 75.221338 -257.786632)
				(xy 75.460098 -257.786632) (xy 75.721718 -258.048252) (xy 76.034138 -258.048252) (xy 76.082398 -257.999992)
				(xy 76.638658 -257.999992) (xy 76.638658 -258.005072) (xy 76.801218 -258.167632) (xy 76.928218 -258.167632)
				(xy 77.382878 -258.622292) (xy 77.888338 -258.622292) (xy 78.127098 -258.861052) (xy 78.264258 -258.861052)
				(xy 78.596998 -259.193792) (xy 78.955138 -259.193792) (xy 79.221838 -259.460492) (xy 79.503778 -259.460492)
				(xy 79.783178 -259.739892) (xy 80.072738 -259.739892) (xy 80.431894 -260.099048) (xy 80.894682 -260.099048)
				(xy 81.050638 -260.255004) (xy 78.343252 -262.962644) (xy 76.402692 -264.903204) (xy 76.123292 -264.903204)
				(xy 76.060046 -264.903204) (xy 74.995024 -265.968226) (xy 74.995024 -266.03706) (xy 74.995024 -267.491972)
				(xy 74.554842 -267.932154) (xy 74.554842 -267.998956) (xy 75.917298 -269.361412) (xy 75.917298 -269.673578)
				(xy 76.075032 -269.831312) (xy 76.075032 -272.332704) (xy 75.644502 -272.763234) (xy 73.865486 -276.010624)
				(xy 73.865486 -276.775164) (xy 72.397366 -278.243284) (xy 72.369426 -278.271224) (xy 72.368918 -278.271224)
				(xy 72.095614 -278.544528) (xy 72.147938 -278.596852) (xy 73.969118 -280.418032) (xy 73.969118 -280.705052)
				(xy 74.136758 -280.872692) (xy 74.151998 -280.872692) (xy 74.609198 -281.329892) (xy 74.609198 -281.340052)
				(xy 74.444098 -281.505152) (xy 74.444098 -281.721052) (xy 75.117198 -282.394152) (xy 75.228958 -282.394152)
				(xy 75.768708 -282.933902) (xy 75.768708 -282.961842) (xy 75.412346 -283.318204) (xy 75.381358 -283.349192)
				(xy 75.381358 -283.399992) (xy 77.101446 -285.12008) (xy 77.101446 -285.489904) (xy 77.101446 -285.602172)
				(xy 77.558646 -286.059372) (xy 77.558646 -286.709104) (xy 77.561186 -286.711644) (xy 77.561186 -286.80156)
				(xy 78.085188 -287.325562) (xy 77.609954 -287.800796) (xy 77.609954 -288.026348) (xy 77.842618 -288.259012)
				(xy 78.06817 -288.259012) (xy 78.185264 -288.376106) (xy 78.185264 -289.18281) (xy 78.371446 -289.368992)
				(xy 78.104238 -289.6362) (xy 78.104238 -290.075112) (xy 79.585058 -291.555932) (xy 79.585058 -291.561012)
				(xy 79.384906 -291.76091) (xy 79.384906 -291.87902) (xy 80.123538 -292.617652) (xy 80.123538 -292.632892)
				(xy 80.093058 -292.663372) (xy 80.093058 -292.734492) (xy 80.585818 -293.227252) (xy 80.585818 -293.283132)
				(xy 80.3275 -293.541704) (xy 81.01965 -294.233854) (xy 80.562704 -294.6908) (xy 80.545178 -294.708326)
				(xy 80.545178 -294.791892) (xy 81.203038 -295.449752) (xy 81.203038 -295.503092) (xy 80.85709 -295.849294)
				(xy 80.85709 -295.952164) (xy 81.406238 -296.501312) (xy 81.406238 -296.613072) (xy 81.78165 -296.988484)
				(xy 81.78165 -297.026584) (xy 81.590642 -297.217846) (xy 81.578958 -297.22953) (xy 81.578958 -297.326812)
				(xy 84.773008 -300.520862)
			)
		)
	)
	(zone
		(layer "F.Cu")
		(hatch none 0.5)
		(connect_pads
			(clearance 0)
		)
		(min_thickness 0.25)
		(keepout
			(tracks allowed)
			(vias allowed)
			(pads allowed)
			(copperpour allowed)
			(footprints allowed)
		)
		(placement
			(enabled no)
			(sheetname "")
		)
		(fill
			(thermal_gap 0.5)
			(thermal_bridge_width 0.5)
			(island_removal_mode 0)
		)
		(polygon
			(pts
				(xy 63.900812 -207.316578) (xy 63.900812 -206.87284) (xy 66.237612 -206.87284) (xy 66.237612 -207.316578)
			)
		)
	)
	(zone
		(layer "F.Cu")
		(hatch none 0.5)
		(connect_pads
			(clearance 0)
		)
		(min_thickness 0.25)
		(keepout
			(tracks allowed)
			(vias allowed)
			(pads allowed)
			(copperpour allowed)
			(footprints allowed)
		)
		(placement
			(enabled no)
			(sheetname "")
		)
		(fill
			(thermal_gap 0.5)
			(thermal_bridge_width 0.5)
			(island_removal_mode 0)
		)
		(polygon
			(pts
				(xy 304.319178 -280.416508) (xy 304.319178 -279.97277) (xy 306.644294 -279.97277) (xy 306.644294 -280.416508)
			)
		)
	)
	(zone
		(layer "F.Cu")
		(hatch none 0.5)
		(connect_pads
			(clearance 0)
		)
		(min_thickness 0.25)
		(keepout
			(tracks allowed)
			(vias allowed)
			(pads allowed)
			(copperpour allowed)
			(footprints allowed)
		)
		(placement
			(enabled no)
			(sheetname "")
		)
		(fill
			(thermal_gap 0.5)
			(thermal_bridge_width 0.5)
			(island_removal_mode 0)
		)
		(polygon
			(pts
				(xy 282.030932 -120.69953) (xy 282.030932 -101.852476) (xy 300.877986 -101.852476) (xy 300.877986 -120.69953)
			)
		)
	)
	(zone
		(layer "F.Cu")
		(hatch none 0.5)
		(connect_pads
			(clearance 0)
		)
		(min_thickness 0.25)
		(keepout
			(tracks allowed)
			(vias allowed)
			(pads allowed)
			(copperpour allowed)
			(footprints allowed)
		)
		(placement
			(enabled no)
			(sheetname "")
		)
		(fill
			(thermal_gap 0.5)
			(thermal_bridge_width 0.5)
			(island_removal_mode 0)
		)
		(polygon
			(pts
				(xy 328.22388 -73.396348) (xy 330.02728 -73.396348) (xy 330.23048 -73.193148) (xy 330.23048 -72.050148)
				(xy 329.92568 -71.745348) (xy 328.88428 -71.745348) (xy 328.12228 -72.507348) (xy 328.12228 -73.294748)
			)
		)
	)
	(zone
		(layer "F.Cu")
		(hatch none 0.5)
		(connect_pads
			(clearance 0)
		)
		(min_thickness 0.25)
		(keepout
			(tracks allowed)
			(vias allowed)
			(pads allowed)
			(copperpour allowed)
			(footprints allowed)
		)
		(placement
			(enabled no)
			(sheetname "")
		)
		(fill
			(thermal_gap 0.5)
			(thermal_bridge_width 0.5)
			(island_removal_mode 0)
		)
		(polygon
			(pts
				(xy 76.438252 -410.948886) (xy 76.438252 -406.105868) (xy 78.322678 -406.105868) (xy 78.322678 -410.948886)
			)
		)
	)
	(zone
		(layer "F.Cu")
		(hatch none 0.5)
		(connect_pads
			(clearance 0)
		)
		(min_thickness 0.25)
		(keepout
			(tracks allowed)
			(vias allowed)
			(pads allowed)
			(copperpour allowed)
			(footprints allowed)
		)
		(placement
			(enabled no)
			(sheetname "")
		)
		(fill
			(thermal_gap 0.5)
			(thermal_bridge_width 0.5)
			(island_removal_mode 0)
		)
		(polygon
			(pts
				(xy 428.363126 -314.304934) (xy 428.363126 -314.076334) (xy 430.395126 -314.076334) (xy 430.395126 -314.304934)
			)
		)
	)
	(zone
		(layer "F.Cu")
		(hatch none 0.5)
		(connect_pads
			(clearance 0)
		)
		(min_thickness 0.25)
		(keepout
			(tracks allowed)
			(vias allowed)
			(pads allowed)
			(copperpour allowed)
			(footprints allowed)
		)
		(placement
			(enabled no)
			(sheetname "")
		)
		(fill
			(thermal_gap 0.5)
			(thermal_bridge_width 0.5)
			(island_removal_mode 0)
		)
		(polygon
			(pts
				(xy 59.822842 -302.51654) (xy 59.822842 -302.072802) (xy 62.147958 -302.072802) (xy 62.147958 -302.51654)
			)
		)
	)
	(zone
		(layer "F.Cu")
		(hatch none 0.5)
		(connect_pads
			(clearance 0)
		)
		(min_thickness 0.25)
		(keepout
			(tracks allowed)
			(vias allowed)
			(pads allowed)
			(copperpour allowed)
			(footprints allowed)
		)
		(placement
			(enabled no)
			(sheetname "")
		)
		(fill
			(thermal_gap 0.5)
			(thermal_bridge_width 0.5)
			(island_removal_mode 0)
		)
		(polygon
			(pts
				(xy 192.066926 -211.2264) (xy 194.098926 -211.2264) (xy 194.098926 -211.455) (xy 192.066926 -211.455)
				(xy 191.930782 -211.455) (xy 191.883792 -211.455) (xy 191.883792 -211.2264) (xy 191.930782 -211.2264)
			)
		)
	)
	(zone
		(layer "F.Cu")
		(hatch none 0.5)
		(connect_pads
			(clearance 0)
		)
		(min_thickness 0.25)
		(keepout
			(tracks allowed)
			(vias allowed)
			(pads allowed)
			(copperpour allowed)
			(footprints allowed)
		)
		(placement
			(enabled no)
			(sheetname "")
		)
		(fill
			(thermal_gap 0.5)
			(thermal_bridge_width 0.5)
			(island_removal_mode 0)
		)
		(polygon
			(pts
				(xy 440.006994 -281.776424) (xy 442.038994 -281.776424) (xy 442.038994 -282.005024) (xy 440.006994 -282.005024)
				(xy 439.87085 -282.005024) (xy 439.82386 -282.005024) (xy 439.71591 -282.005024) (xy 439.71591 -281.776424)
				(xy 439.82386 -281.776424) (xy 439.87085 -281.776424)
			)
		)
	)
	(zone
		(layer "F.Cu")
		(hatch none 0.5)
		(connect_pads
			(clearance 0)
		)
		(min_thickness 0.25)
		(keepout
			(tracks allowed)
			(vias allowed)
			(pads allowed)
			(copperpour allowed)
			(footprints allowed)
		)
		(placement
			(enabled no)
			(sheetname "")
		)
		(fill
			(thermal_gap 0.5)
			(thermal_bridge_width 0.5)
			(island_removal_mode 0)
		)
		(polygon
			(pts
				(xy 340.44128 -339.220048) (xy 340.44128 -335.384648) (xy 346.8751 -335.384648) (xy 346.8751 -339.220048)
			)
		)
	)
	(zone
		(layer "F.Cu")
		(hatch none 0.5)
		(connect_pads
			(clearance 0)
		)
		(min_thickness 0.25)
		(keepout
			(tracks allowed)
			(vias allowed)
			(pads allowed)
			(copperpour allowed)
			(footprints allowed)
		)
		(placement
			(enabled no)
			(sheetname "")
		)
		(fill
			(thermal_gap 0.5)
			(thermal_bridge_width 0.5)
			(island_removal_mode 0)
		)
		(polygon
			(pts
				(xy 405.731726 -208.90484) (xy 405.731726 -208.67624) (xy 407.763726 -208.67624) (xy 407.763726 -208.90484)
			)
		)
	)
	(zone
		(layer "F.Cu")
		(hatch none 0.5)
		(connect_pads
			(clearance 0)
		)
		(min_thickness 0.25)
		(keepout
			(tracks allowed)
			(vias allowed)
			(pads allowed)
			(copperpour allowed)
			(footprints allowed)
		)
		(placement
			(enabled no)
			(sheetname "")
		)
		(fill
			(thermal_gap 0.5)
			(thermal_bridge_width 0.5)
			(island_removal_mode 0)
		)
		(polygon
			(pts
				(xy 259.056378 -299.116496) (xy 259.056378 -298.672758) (xy 261.381494 -298.672758) (xy 261.381494 -299.116496)
			)
		)
	)
	(zone
		(layer "F.Cu")
		(hatch none 0.5)
		(connect_pads
			(clearance 0)
		)
		(min_thickness 0.25)
		(keepout
			(tracks allowed)
			(vias allowed)
			(pads allowed)
			(copperpour allowed)
			(footprints allowed)
		)
		(placement
			(enabled no)
			(sheetname "")
		)
		(fill
			(thermal_gap 0.5)
			(thermal_bridge_width 0.5)
			(island_removal_mode 0)
		)
		(polygon
			(pts
				(xy 192.066926 -280.076402) (xy 194.098926 -280.076402) (xy 194.098926 -280.305002) (xy 192.066926 -280.305002)
				(xy 191.930782 -280.305002) (xy 191.883792 -280.305002) (xy 191.883792 -280.076402) (xy 191.930782 -280.076402)
			)
		)
	)
	(zone
		(layer "F.Cu")
		(hatch none 0.5)
		(connect_pads
			(clearance 0)
		)
		(min_thickness 0.25)
		(keepout
			(tracks allowed)
			(vias allowed)
			(pads allowed)
			(copperpour allowed)
			(footprints allowed)
		)
		(placement
			(enabled no)
			(sheetname "")
		)
		(fill
			(thermal_gap 0.5)
			(thermal_bridge_width 0.5)
			(island_removal_mode 0)
		)
		(polygon
			(pts
				(xy 157.803088 -410.948886) (xy 157.803088 -406.105868) (xy 159.687514 -406.105868) (xy 159.687514 -410.948886)
			)
		)
	)
	(zone
		(layer "F.Cu")
		(hatch none 0.5)
		(connect_pads
			(clearance 0)
		)
		(min_thickness 0.25)
		(keepout
			(tracks allowed)
			(vias allowed)
			(pads allowed)
			(copperpour allowed)
			(footprints allowed)
		)
		(placement
			(enabled no)
			(sheetname "")
		)
		(fill
			(thermal_gap 0.5)
			(thermal_bridge_width 0.5)
			(island_removal_mode 0)
		)
		(polygon
			(pts
				(xy 14.560042 -302.51654) (xy 14.560042 -302.072802) (xy 16.885158 -302.072802) (xy 16.885158 -302.51654)
			)
		)
	)
	(zone
		(layer "F.Cu")
		(hatch none 0.5)
		(connect_pads
			(clearance 0)
		)
		(min_thickness 0.25)
		(keepout
			(tracks allowed)
			(vias allowed)
			(pads allowed)
			(copperpour allowed)
			(footprints allowed)
		)
		(placement
			(enabled no)
			(sheetname "")
		)
		(fill
			(thermal_gap 0.5)
			(thermal_bridge_width 0.5)
			(island_removal_mode 0)
		)
		(polygon
			(pts
				(xy 155.22194 -39.637208) (xy 155.22194 -35.971988) (xy 158.98622 -35.971988) (xy 158.98622 -39.637208)
			)
		)
	)
	(zone
		(layer "F.Cu")
		(hatch none 0.5)
		(connect_pads
			(clearance 0)
		)
		(min_thickness 0.25)
		(keepout
			(tracks allowed)
			(vias allowed)
			(pads allowed)
			(copperpour allowed)
			(footprints allowed)
		)
		(placement
			(enabled no)
			(sheetname "")
		)
		(fill
			(thermal_gap 0.5)
			(thermal_bridge_width 0.5)
			(island_removal_mode 0)
		)
		(polygon
			(pts
				(xy 112.434116 -332.908402) (xy 110.618016 -332.908402) (xy 110.618016 -331.529182) (xy 112.434116 -331.529182)
			)
		)
	)
	(zone
		(layer "F.Cu")
		(hatch none 0.5)
		(connect_pads
			(clearance 0)
		)
		(min_thickness 0.25)
		(keepout
			(tracks allowed)
			(vias allowed)
			(pads allowed)
			(copperpour allowed)
			(footprints allowed)
		)
		(placement
			(enabled no)
			(sheetname "")
		)
		(fill
			(thermal_gap 0.5)
			(thermal_bridge_width 0.5)
			(island_removal_mode 0)
		)
		(polygon
			(pts
				(xy 304.319178 -270.622776) (xy 306.644294 -270.622776) (xy 306.697634 -270.622776) (xy 306.697634 -271.53362)
				(xy 304.197004 -271.53362) (xy 304.197004 -270.622776)
			)
		)
	)
	(zone
		(layer "F.Cu")
		(hatch none 0.5)
		(connect_pads
			(clearance 0)
		)
		(min_thickness 0.25)
		(keepout
			(tracks allowed)
			(vias allowed)
			(pads allowed)
			(copperpour allowed)
			(footprints allowed)
		)
		(placement
			(enabled no)
			(sheetname "")
		)
		(fill
			(thermal_gap 0.5)
			(thermal_bridge_width 0.5)
			(island_removal_mode 0)
		)
		(polygon
			(pts
				(xy 161.891726 -252.25502) (xy 161.891726 -252.02642) (xy 163.923726 -252.02642) (xy 163.923726 -252.25502)
				(xy 163.923726 -252.847602) (xy 161.891726 -252.847602)
			)
		)
	)
	(zone
		(layer "F.Cu")
		(hatch none 0.5)
		(connect_pads
			(clearance 0)
		)
		(min_thickness 0.25)
		(keepout
			(tracks allowed)
			(vias allowed)
			(pads allowed)
			(copperpour allowed)
			(footprints allowed)
		)
		(placement
			(enabled no)
			(sheetname "")
		)
		(fill
			(thermal_gap 0.5)
			(thermal_bridge_width 0.5)
			(island_removal_mode 0)
		)
		(polygon
			(pts
				(xy 440.006994 -239.276382) (xy 442.038994 -239.276382) (xy 442.038994 -239.278668) (xy 442.21781 -239.278668)
				(xy 442.21781 -239.515904) (xy 442.355732 -239.515904) (xy 442.398912 -239.559084) (xy 442.398912 -239.691926)
				(xy 442.398912 -239.995964) (xy 442.326268 -240.068608) (xy 439.786014 -240.068608) (xy 439.64479 -239.927384)
				(xy 439.64479 -239.73028) (xy 439.726324 -239.648746) (xy 439.726324 -239.276382) (xy 439.82386 -239.276382)
				(xy 439.87085 -239.276382)
			)
		)
	)
	(zone
		(layer "F.Cu")
		(hatch none 0.5)
		(connect_pads
			(clearance 0)
		)
		(min_thickness 0.25)
		(keepout
			(tracks allowed)
			(vias allowed)
			(pads allowed)
			(copperpour allowed)
			(footprints allowed)
		)
		(placement
			(enabled no)
			(sheetname "")
		)
		(fill
			(thermal_gap 0.5)
			(thermal_bridge_width 0.5)
			(island_removal_mode 0)
		)
		(polygon
			(pts
				(xy 352.213418 -332.908402) (xy 350.397318 -332.908402) (xy 350.397318 -331.529182) (xy 352.213418 -331.529182)
			)
		)
	)
	(zone
		(layer "F.Cu")
		(hatch none 0.5)
		(connect_pads
			(clearance 0)
		)
		(min_thickness 0.25)
		(keepout
			(tracks allowed)
			(vias allowed)
			(pads allowed)
			(copperpour allowed)
			(footprints allowed)
		)
		(placement
			(enabled no)
			(sheetname "")
		)
		(fill
			(thermal_gap 0.5)
			(thermal_bridge_width 0.5)
			(island_removal_mode 0)
		)
		(polygon
			(pts
				(xy 176.979326 -285.176214) (xy 179.011326 -285.176214) (xy 179.011326 -285.404814) (xy 176.979326 -285.404814)
				(xy 176.848008 -285.404814) (xy 176.8221 -285.404814) (xy 176.8221 -285.176214) (xy 176.848008 -285.176214)
			)
		)
	)
	(zone
		(layer "F.Cu")
		(hatch none 0.5)
		(connect_pads
			(clearance 0)
		)
		(min_thickness 0.25)
		(keepout
			(tracks allowed)
			(vias allowed)
			(pads allowed)
			(copperpour allowed)
			(footprints allowed)
		)
		(placement
			(enabled no)
			(sheetname "")
		)
		(fill
			(thermal_gap 0.5)
			(thermal_bridge_width 0.5)
			(island_removal_mode 0)
		)
		(polygon
			(pts
				(xy 409.831794 -308.354984) (xy 409.831794 -308.126384) (xy 411.863794 -308.126384) (xy 411.863794 -308.354984)
			)
		)
	)
	(zone
		(layer "F.Cu")
		(hatch none 0.5)
		(connect_pads
			(clearance 0)
		)
		(min_thickness 0.25)
		(keepout
			(tracks allowed)
			(vias allowed)
			(pads allowed)
			(copperpour allowed)
			(footprints allowed)
		)
		(placement
			(enabled no)
			(sheetname "")
		)
		(fill
			(thermal_gap 0.5)
			(thermal_bridge_width 0.5)
			(island_removal_mode 0)
		)
		(polygon
			(pts
				(xy 161.891726 -245.454932) (xy 161.891726 -245.226332) (xy 163.923726 -245.226332) (xy 163.923726 -245.454932)
			)
		)
	)
	(zone
		(layer "F.Cu")
		(hatch none 0.5)
		(connect_pads
			(clearance 0)
		)
		(min_thickness 0.25)
		(keepout
			(tracks allowed)
			(vias allowed)
			(pads allowed)
			(copperpour allowed)
			(footprints not_allowed)
		)
		(placement
			(enabled no)
			(sheetname "")
		)
		(fill
			(thermal_gap 0.5)
			(thermal_bridge_width 0.5)
			(island_removal_mode 0)
		)
		(polygon
			(pts
				(xy 123.916948 -52.049934) (xy 123.916948 -42.049954) (xy 110.916974 -42.049954) (xy 110.916974 -52.049934)
			)
		)
	)
	(zone
		(layer "F.Cu")
		(hatch none 0.5)
		(connect_pads
			(clearance 0)
		)
		(min_thickness 0.25)
		(keepout
			(tracks allowed)
			(vias allowed)
			(pads allowed)
			(copperpour allowed)
			(footprints allowed)
		)
		(placement
			(enabled no)
			(sheetname "")
		)
		(fill
			(thermal_gap 0.5)
			(thermal_bridge_width 0.5)
			(island_removal_mode 0)
		)
		(polygon
			(pts
				(xy 443.450726 -211.455) (xy 443.450726 -211.2264) (xy 445.482726 -211.2264) (xy 445.482726 -211.455)
			)
		)
	)
	(zone
		(layer "F.Cu")
		(hatch none 0.5)
		(connect_pads
			(clearance 0)
		)
		(min_thickness 0.25)
		(keepout
			(tracks allowed)
			(vias allowed)
			(pads allowed)
			(copperpour allowed)
			(footprints allowed)
		)
		(placement
			(enabled no)
			(sheetname "")
		)
		(fill
			(thermal_gap 0.5)
			(thermal_bridge_width 0.5)
			(island_removal_mode 0)
		)
		(polygon
			(pts
				(xy 311.89168 -240.872772) (xy 314.15228 -240.872772) (xy 314.244228 -240.872772) (xy 314.244228 -241.79276)
				(xy 311.735724 -241.79276) (xy 311.735724 -240.872772)
			)
		)
	)
	(zone
		(layer "F.Cu")
		(hatch none 0.5)
		(connect_pads
			(clearance 0)
		)
		(min_thickness 0.25)
		(keepout
			(tracks allowed)
			(vias allowed)
			(pads allowed)
			(copperpour allowed)
			(footprints allowed)
		)
		(placement
			(enabled no)
			(sheetname "")
		)
		(fill
			(thermal_gap 0.5)
			(thermal_bridge_width 0.5)
			(island_removal_mode 0)
		)
		(polygon
			(pts
				(xy 407.774902 -270.95704) (xy 405.742902 -270.95704) (xy 405.742902 -270.954754) (xy 405.564086 -270.954754)
				(xy 405.564086 -270.717518) (xy 405.509984 -270.717518) (xy 405.382984 -270.590518) (xy 405.382984 -270.541496)
				(xy 405.382984 -270.237458) (xy 405.455628 -270.164814) (xy 407.995882 -270.164814) (xy 408.137106 -270.306038)
				(xy 408.137106 -270.503142) (xy 408.055572 -270.584676) (xy 407.958036 -270.682212) (xy 407.958036 -270.95704)
				(xy 407.911046 -270.95704)
			)
		)
	)
	(zone
		(layer "F.Cu")
		(hatch none 0.5)
		(connect_pads
			(clearance 0)
		)
		(min_thickness 0.25)
		(keepout
			(tracks allowed)
			(vias allowed)
			(pads allowed)
			(copperpour allowed)
			(footprints allowed)
		)
		(placement
			(enabled no)
			(sheetname "")
		)
		(fill
			(thermal_gap 0.5)
			(thermal_bridge_width 0.5)
			(island_removal_mode 0)
		)
		(polygon
			(pts
				(xy 26.20391 -196.266562) (xy 26.20391 -195.822824) (xy 28.529026 -195.822824) (xy 28.529026 -196.266562)
			)
		)
	)
	(zone
		(layer "F.Cu")
		(hatch none 0.5)
		(connect_pads
			(clearance 0)
		)
		(min_thickness 0.25)
		(keepout
			(tracks allowed)
			(vias allowed)
			(pads allowed)
			(copperpour allowed)
			(footprints allowed)
		)
		(placement
			(enabled no)
			(sheetname "")
		)
		(fill
			(thermal_gap 0.5)
			(thermal_bridge_width 0.5)
			(island_removal_mode 0)
		)
		(polygon
			(pts
				(xy 458.538326 -292.204902) (xy 458.538326 -291.976302) (xy 460.570326 -291.976302) (xy 460.570326 -292.204902)
			)
		)
	)
	(zone
		(layer "F.Cu")
		(hatch none 0.5)
		(connect_pads
			(clearance 0)
		)
		(min_thickness 0.25)
		(keepout
			(tracks allowed)
			(vias allowed)
			(pads allowed)
			(copperpour allowed)
			(footprints allowed)
		)
		(placement
			(enabled no)
			(sheetname "")
		)
		(fill
			(thermal_gap 0.5)
			(thermal_bridge_width 0.5)
			(island_removal_mode 0)
		)
		(polygon
			(pts
				(xy 44.735242 -289.766502) (xy 44.735242 -289.322764) (xy 47.060358 -289.322764) (xy 47.060358 -289.766502)
			)
		)
	)
	(zone
		(layer "F.Cu")
		(hatch none 0.5)
		(connect_pads
			(clearance 0)
		)
		(min_thickness 0.25)
		(keepout
			(tracks allowed)
			(vias allowed)
			(pads allowed)
			(copperpour allowed)
			(footprints allowed)
		)
		(placement
			(enabled no)
			(sheetname "")
		)
		(fill
			(thermal_gap 0.5)
			(thermal_bridge_width 0.5)
			(island_removal_mode 0)
		)
		(polygon
			(pts
				(xy 180.423058 -301.554896) (xy 180.423058 -301.326296) (xy 182.455058 -301.326296) (xy 182.455058 -301.554896)
			)
		)
	)
	(zone
		(layer "F.Cu")
		(hatch none 0.5)
		(connect_pads
			(clearance 0)
		)
		(min_thickness 0.25)
		(keepout
			(tracks allowed)
			(vias allowed)
			(pads allowed)
			(copperpour allowed)
			(footprints allowed)
		)
		(placement
			(enabled no)
			(sheetname "")
		)
		(fill
			(thermal_gap 0.5)
			(thermal_bridge_width 0.5)
			(island_removal_mode 0)
		)
		(polygon
			(pts
				(xy 192.066926 -212.926422) (xy 194.098926 -212.926422) (xy 194.098926 -213.155022) (xy 192.066926 -213.155022)
				(xy 191.930782 -213.155022) (xy 191.883792 -213.155022) (xy 191.883792 -212.926422) (xy 191.930782 -212.926422)
			)
		)
	)
	(zone
		(layer "F.Cu")
		(hatch none 0.5)
		(connect_pads
			(clearance 0)
		)
		(min_thickness 0.25)
		(keepout
			(tracks allowed)
			(vias allowed)
			(pads allowed)
			(copperpour allowed)
			(footprints allowed)
		)
		(placement
			(enabled no)
			(sheetname "")
		)
		(fill
			(thermal_gap 0.5)
			(thermal_bridge_width 0.5)
			(island_removal_mode 0)
		)
		(polygon
			(pts
				(xy 455.094594 -275.206968) (xy 457.126594 -275.206968) (xy 457.126594 -274.978368) (xy 455.094594 -274.978368)
				(xy 454.963276 -274.978368) (xy 454.937368 -274.978368) (xy 454.937368 -275.206968) (xy 454.963276 -275.206968)
			)
		)
	)
	(zone
		(layer "F.Cu")
		(hatch none 0.5)
		(connect_pads
			(clearance 0)
		)
		(min_thickness 0.25)
		(keepout
			(tracks allowed)
			(vias allowed)
			(pads allowed)
			(copperpour allowed)
			(footprints allowed)
		)
		(placement
			(enabled no)
			(sheetname "")
		)
		(fill
			(thermal_gap 0.5)
			(thermal_bridge_width 0.5)
			(island_removal_mode 0)
		)
		(polygon
			(pts
				(xy 274.143978 -299.116496) (xy 274.143978 -298.672758) (xy 276.469094 -298.672758) (xy 276.469094 -299.116496)
			)
		)
	)
	(zone
		(layer "F.Cu")
		(hatch none 0.5)
		(connect_pads
			(clearance 0)
		)
		(min_thickness 0.25)
		(keepout
			(tracks allowed)
			(vias allowed)
			(pads allowed)
			(copperpour allowed)
			(footprints allowed)
		)
		(placement
			(enabled no)
			(sheetname "")
		)
		(fill
			(thermal_gap 0.5)
			(thermal_bridge_width 0.5)
			(island_removal_mode 0)
		)
		(polygon
			(pts
				(xy 440.006994 -313.226196) (xy 442.038994 -313.226196) (xy 442.038994 -313.454796) (xy 440.006994 -313.454796)
				(xy 439.875676 -313.454796) (xy 439.849768 -313.454796) (xy 439.849768 -313.226196) (xy 439.875676 -313.226196)
			)
		)
	)
	(zone
		(layer "F.Cu")
		(hatch none 0.5)
		(connect_pads
			(clearance 0)
		)
		(min_thickness 0.25)
		(keepout
			(tracks allowed)
			(vias allowed)
			(pads allowed)
			(copperpour allowed)
			(footprints allowed)
		)
		(placement
			(enabled no)
			(sheetname "")
		)
		(fill
			(thermal_gap 0.5)
			(thermal_bridge_width 0.5)
			(island_removal_mode 0)
		)
		(polygon
			(pts
				(xy 413.275526 -273.276314) (xy 415.307526 -273.276314) (xy 415.307526 -273.2786) (xy 415.486342 -273.2786)
				(xy 415.676588 -273.2786) (xy 415.744152 -273.2786) (xy 415.744152 -273.559016) (xy 415.806128 -273.559016)
				(xy 415.806128 -274.06854) (xy 415.5948 -274.06854) (xy 413.054546 -274.06854) (xy 412.794704 -274.06854)
				(xy 412.7881 -274.06854) (xy 412.7881 -273.591782) (xy 412.912306 -273.591782) (xy 412.912306 -273.276314)
				(xy 412.950914 -273.276314) (xy 412.994856 -273.276314) (xy 413.092392 -273.276314) (xy 413.139382 -273.276314)
			)
		)
	)
	(zone
		(layer "F.Cu")
		(hatch none 0.5)
		(connect_pads
			(clearance 0)
		)
		(min_thickness 0.25)
		(keepout
			(tracks allowed)
			(vias allowed)
			(pads allowed)
			(copperpour allowed)
			(footprints allowed)
		)
		(placement
			(enabled no)
			(sheetname "")
		)
		(fill
			(thermal_gap 0.5)
			(thermal_bridge_width 0.5)
			(island_removal_mode 0)
		)
		(polygon
			(pts
				(xy 440.006994 -264.776204) (xy 442.038994 -264.776204) (xy 442.038994 -265.004804) (xy 440.006994 -265.004804)
				(xy 439.84037 -265.004804) (xy 439.718704 -265.004804) (xy 439.718704 -264.776204) (xy 439.84037 -264.776204)
			)
		)
	)
	(zone
		(layer "F.Cu")
		(hatch none 0.5)
		(connect_pads
			(clearance 0)
		)
		(min_thickness 0.25)
		(keepout
			(tracks allowed)
			(vias allowed)
			(pads allowed)
			(copperpour allowed)
			(footprints allowed)
		)
		(placement
			(enabled no)
			(sheetname "")
		)
		(fill
			(thermal_gap 0.5)
			(thermal_bridge_width 0.5)
			(island_removal_mode 0)
		)
		(polygon
			(pts
				(xy 44.735242 -208.166462) (xy 44.735242 -207.722724) (xy 47.060358 -207.722724) (xy 47.060358 -208.166462)
			)
		)
	)
	(zone
		(layer "F.Cu")
		(hatch none 0.5)
		(connect_pads
			(clearance 0)
		)
		(min_thickness 0.25)
		(keepout
			(tracks allowed)
			(vias allowed)
			(pads allowed)
			(copperpour allowed)
			(footprints allowed)
		)
		(placement
			(enabled no)
			(sheetname "")
		)
		(fill
			(thermal_gap 0.5)
			(thermal_bridge_width 0.5)
			(island_removal_mode 0)
		)
		(polygon
			(pts
				(xy 274.143978 -214.96655) (xy 274.143978 -214.522812) (xy 276.469094 -214.522812) (xy 276.469094 -214.96655)
			)
		)
	)
	(zone
		(layer "F.Cu")
		(hatch none 0.5)
		(connect_pads
			(clearance 0)
		)
		(min_thickness 0.25)
		(keepout
			(tracks not_allowed)
			(vias allowed)
			(pads allowed)
			(copperpour not_allowed)
			(footprints allowed)
		)
		(placement
			(enabled no)
			(sheetname "")
		)
		(fill
			(thermal_gap 0.5)
			(thermal_bridge_width 0.5)
			(island_removal_mode 0)
		)
		(polygon
			(pts
				(xy 169.979848 -356.098602) (xy 173.9138 -356.098602) (xy 173.9138 -356.03561) (xy 173.79188 -355.91369)
				(xy 172.367702 -355.91369) (xy 172.367702 -353.75469) (xy 174.524416 -353.75469) (xy 174.524416 -353.505008)
				(xy 172.21962 -353.505008) (xy 172.21962 -353.825048) (xy 172.076364 -353.825048) (xy 172.076364 -355.858064)
				(xy 170.222164 -355.858064) (xy 170.222164 -355.617018) (xy 169.979848 -355.617018)
			)
		)
	)
	(zone
		(layer "F.Cu")
		(hatch none 0.5)
		(connect_pads
			(clearance 0)
		)
		(min_thickness 0.25)
		(keepout
			(tracks allowed)
			(vias allowed)
			(pads allowed)
			(copperpour allowed)
			(footprints allowed)
		)
		(placement
			(enabled no)
			(sheetname "")
		)
		(fill
			(thermal_gap 0.5)
			(thermal_bridge_width 0.5)
			(island_removal_mode 0)
		)
		(polygon
			(pts
				(xy 14.560042 -211.566506) (xy 14.560042 -211.122768) (xy 16.885158 -211.122768) (xy 16.885158 -211.566506)
			)
		)
	)
	(zone
		(layer "F.Cu")
		(hatch none 0.5)
		(connect_pads
			(clearance 0)
		)
		(min_thickness 0.25)
		(keepout
			(tracks not_allowed)
			(vias allowed)
			(pads allowed)
			(copperpour not_allowed)
			(footprints allowed)
		)
		(placement
			(enabled no)
			(sheetname "")
		)
		(fill
			(thermal_gap 0.5)
			(thermal_bridge_width 0.5)
			(island_removal_mode 0)
		)
		(polygon
			(pts
				(arc
					(start 13.702284 -32.130238)
					(mid 17.376526 -31.99321)
					(end 17.239742 -28.318968)
				)
				(arc
					(start 16.067024 -27.230578)
					(mid 12.392782 -27.367606)
					(end 12.529566 -31.041848)
				)
			)
		)
	)
	(zone
		(layer "F.Cu")
		(hatch none 0.5)
		(connect_pads
			(clearance 0)
		)
		(min_thickness 0.25)
		(keepout
			(tracks not_allowed)
			(vias allowed)
			(pads allowed)
			(copperpour not_allowed)
			(footprints allowed)
		)
		(placement
			(enabled no)
			(sheetname "")
		)
		(fill
			(thermal_gap 0.5)
			(thermal_bridge_width 0.5)
			(island_removal_mode 0)
		)
		(polygon
			(pts
				(arc
					(start 98.500184 -435.59984)
					(mid 100.50018 -433.599844)
					(end 102.500176 -435.59984)
				)
				(arc
					(start 102.500176 -435.59984)
					(mid 100.50018 -437.599836)
					(end 98.500184 -435.59984)
				)
			)
		)
	)
	(zone
		(layer "F.Cu")
		(hatch none 0.5)
		(connect_pads
			(clearance 0)
		)
		(min_thickness 0.25)
		(keepout
			(tracks allowed)
			(vias allowed)
			(pads allowed)
			(copperpour allowed)
			(footprints allowed)
		)
		(placement
			(enabled no)
			(sheetname "")
		)
		(fill
			(thermal_gap 0.5)
			(thermal_bridge_width 0.5)
			(island_removal_mode 0)
		)
		(polygon
			(pts
				(xy 71.735442 -40.229282) (xy 71.735442 -38.48862) (xy 73.650856 -38.48862) (xy 73.650856 -40.229282)
			)
		)
	)
	(zone
		(layer "F.Cu")
		(hatch none 0.5)
		(connect_pads
			(clearance 0)
		)
		(min_thickness 0.25)
		(keepout
			(tracks allowed)
			(vias allowed)
			(pads allowed)
			(copperpour allowed)
			(footprints allowed)
		)
		(placement
			(enabled no)
			(sheetname "")
		)
		(fill
			(thermal_gap 0.5)
			(thermal_bridge_width 0.5)
			(island_removal_mode 0)
		)
		(polygon
			(pts
				(xy 304.319178 -297.416474) (xy 304.319178 -296.972736) (xy 306.644294 -296.972736) (xy 306.644294 -297.416474)
			)
		)
	)
	(zone
		(layer "F.Cu")
		(hatch none 0.5)
		(connect_pads
			(clearance 0)
		)
		(min_thickness 0.25)
		(keepout
			(tracks allowed)
			(vias allowed)
			(pads allowed)
			(copperpour allowed)
			(footprints not_allowed)
		)
		(placement
			(enabled no)
			(sheetname "")
		)
		(fill
			(thermal_gap 0.5)
			(thermal_bridge_width 0.5)
			(island_removal_mode 0)
		)
		(polygon
			(pts
				(arc
					(start 452.88835 -440.989974)
					(mid 451.610422 -439.101653)
					(end 450.917056 -436.92953)
				)
				(arc
					(start 450.917056 -436.92953)
					(mid 448.10824 -438.002382)
					(end 446.300098 -435.600094)
				)
				(arc
					(start 446.300098 -435.600094)
					(mid 448.10398 -433.199064)
					(end 450.912484 -434.263038)
				)
				(arc
					(start 450.912484 -434.263038)
					(mid 452.117095 -431.202343)
					(end 454.451466 -428.885096)
				)
				(xy 438.69991 -428.885096) (xy 438.69991 -401.385024) (xy 461.199992 -401.385024)
				(arc
					(start 461.199992 -427.96841)
					(mid 462.85373 -428.703079)
					(end 464.300062 -429.790606)
				)
				(arc
					(start 464.300062 -409.528518)
					(mid 464.52834 -408.380416)
					(end 465.178648 -407.40711)
				)
				(arc
					(start 467.007194 -405.578564)
					(mid 467.223898 -405.254244)
					(end 467.300056 -404.871682)
				)
				(xy 467.300056 -398.75587) (xy 437.279034 -398.75587) (xy 437.279034 -403.770084) (xy 438.279286 -403.770084)
				(xy 438.279286 -433.07) (xy 417.599876 -433.07) (xy 417.599876 -440.989974)
			)
		)
	)
	(zone
		(layer "F.Cu")
		(hatch none 0.5)
		(connect_pads
			(clearance 0)
		)
		(min_thickness 0.25)
		(keepout
			(tracks allowed)
			(vias allowed)
			(pads allowed)
			(copperpour allowed)
			(footprints allowed)
		)
		(placement
			(enabled no)
			(sheetname "")
		)
		(fill
			(thermal_gap 0.5)
			(thermal_bridge_width 0.5)
			(island_removal_mode 0)
		)
		(polygon
			(pts
				(xy 14.02334 -107.312968) (xy 14.02334 -104.790748) (xy 17.10944 -104.790748) (xy 17.10944 -107.312968)
			)
		)
	)
	(zone
		(layer "F.Cu")
		(hatch none 0.5)
		(connect_pads
			(clearance 0)
		)
		(min_thickness 0.25)
		(keepout
			(tracks allowed)
			(vias allowed)
			(pads allowed)
			(copperpour allowed)
			(footprints not_allowed)
		)
		(placement
			(enabled no)
			(sheetname "")
		)
		(fill
			(thermal_gap 0.5)
			(thermal_bridge_width 0.5)
			(island_removal_mode 0)
		)
		(polygon
			(pts
				(arc
					(start 132.518912 -354.434902)
					(mid 136.518904 -350.43491)
					(end 140.518896 -354.434902)
				)
				(arc
					(start 140.518896 -354.434902)
					(mid 136.518904 -358.434894)
					(end 132.518912 -354.434902)
				)
			)
		)
	)
	(zone
		(layer "F.Cu")
		(hatch none 0.5)
		(connect_pads
			(clearance 0)
		)
		(min_thickness 0.25)
		(keepout
			(tracks allowed)
			(vias allowed)
			(pads allowed)
			(copperpour allowed)
			(footprints allowed)
		)
		(placement
			(enabled no)
			(sheetname "")
		)
		(fill
			(thermal_gap 0.5)
			(thermal_bridge_width 0.5)
			(island_removal_mode 0)
		)
		(polygon
			(pts
				(xy 274.143978 -210.716622) (xy 274.143978 -210.272884) (xy 276.469094 -210.272884) (xy 276.469094 -210.716622)
			)
		)
	)
	(zone
		(layer "F.Cu")
		(hatch none 0.5)
		(connect_pads
			(clearance 0)
		)
		(min_thickness 0.25)
		(keepout
			(tracks allowed)
			(vias allowed)
			(pads allowed)
			(copperpour allowed)
			(footprints allowed)
		)
		(placement
			(enabled no)
			(sheetname "")
		)
		(fill
			(thermal_gap 0.5)
			(thermal_bridge_width 0.5)
			(island_removal_mode 0)
		)
		(polygon
			(pts
				(xy 307.76291 -197.966584) (xy 307.76291 -197.522846) (xy 310.088026 -197.522846) (xy 310.088026 -197.966584)
			)
		)
	)
	(zone
		(layer "F.Cu")
		(hatch none 0.5)
		(connect_pads
			(clearance 0)
		)
		(min_thickness 0.25)
		(keepout
			(tracks allowed)
			(vias allowed)
			(pads allowed)
			(copperpour allowed)
			(footprints allowed)
		)
		(placement
			(enabled no)
			(sheetname "")
		)
		(fill
			(thermal_gap 0.5)
			(thermal_bridge_width 0.5)
			(island_removal_mode 0)
		)
		(polygon
			(pts
				(xy 458.538326 -208.90484) (xy 458.538326 -208.67624) (xy 460.570326 -208.67624) (xy 460.570326 -208.90484)
			)
		)
	)
	(zone
		(layer "F.Cu")
		(hatch none 0.5)
		(connect_pads
			(clearance 0)
		)
		(min_thickness 0.25)
		(keepout
			(tracks allowed)
			(vias allowed)
			(pads allowed)
			(copperpour allowed)
			(footprints allowed)
		)
		(placement
			(enabled no)
			(sheetname "")
		)
		(fill
			(thermal_gap 0.5)
			(thermal_bridge_width 0.5)
			(island_removal_mode 0)
		)
		(polygon
			(pts
				(xy 29.647642 -301.666656) (xy 29.647642 -301.222918) (xy 31.972758 -301.222918) (xy 31.972758 -301.666656)
			)
		)
	)
	(zone
		(layer "F.Cu")
		(hatch none 0.5)
		(connect_pads
			(clearance 0)
		)
		(min_thickness 0.25)
		(keepout
			(tracks allowed)
			(vias allowed)
			(pads allowed)
			(copperpour allowed)
			(footprints allowed)
		)
		(placement
			(enabled no)
			(sheetname "")
		)
		(fill
			(thermal_gap 0.5)
			(thermal_bridge_width 0.5)
			(island_removal_mode 0)
		)
		(polygon
			(pts
				(xy 289.231578 -220.9165) (xy 289.231578 -220.472762) (xy 291.556694 -220.472762) (xy 291.556694 -220.9165)
			)
		)
	)
	(zone
		(layer "F.Cu")
		(hatch none 0.5)
		(connect_pads
			(clearance 0)
		)
		(min_thickness 0.25)
		(keepout
			(tracks allowed)
			(vias allowed)
			(pads allowed)
			(copperpour allowed)
			(footprints allowed)
		)
		(placement
			(enabled no)
			(sheetname "")
		)
		(fill
			(thermal_gap 0.5)
			(thermal_bridge_width 0.5)
			(island_removal_mode 0)
		)
		(polygon
			(pts
				(xy 176.979326 -195.926456) (xy 179.011326 -195.926456) (xy 179.011326 -196.155056) (xy 176.979326 -196.155056)
				(xy 176.843182 -196.155056) (xy 176.796192 -196.155056) (xy 176.796192 -195.926456) (xy 176.843182 -195.926456)
			)
		)
	)
	(zone
		(layer "F.Cu")
		(hatch none 0.5)
		(connect_pads
			(clearance 0)
		)
		(min_thickness 0.25)
		(keepout
			(tracks allowed)
			(vias allowed)
			(pads allowed)
			(copperpour allowed)
			(footprints allowed)
		)
		(placement
			(enabled no)
			(sheetname "")
		)
		(fill
			(thermal_gap 0.5)
			(thermal_bridge_width 0.5)
			(island_removal_mode 0)
		)
		(polygon
			(pts
				(xy 445.493902 -241.207036) (xy 443.461902 -241.207036) (xy 443.461902 -241.20475) (xy 443.283086 -241.20475)
				(xy 443.283086 -240.967514) (xy 443.145164 -240.967514) (xy 443.101984 -240.924334) (xy 443.101984 -240.791492)
				(xy 443.101984 -240.487454) (xy 443.174628 -240.41481) (xy 445.714882 -240.41481) (xy 445.856106 -240.556034)
				(xy 445.856106 -240.753138) (xy 445.774572 -240.834672) (xy 445.774572 -241.207036) (xy 445.677036 -241.207036)
				(xy 445.630046 -241.207036)
			)
		)
	)
	(zone
		(layer "F.Cu")
		(hatch none 0.5)
		(connect_pads
			(clearance 0)
		)
		(min_thickness 0.25)
		(keepout
			(tracks allowed)
			(vias allowed)
			(pads allowed)
			(copperpour allowed)
			(footprints allowed)
		)
		(placement
			(enabled no)
			(sheetname "")
		)
		(fill
			(thermal_gap 0.5)
			(thermal_bridge_width 0.5)
			(island_removal_mode 0)
		)
		(polygon
			(pts
				(xy 277.58771 -311.01665) (xy 277.58771 -310.572912) (xy 279.912826 -310.572912) (xy 279.912826 -311.01665)
			)
		)
	)
	(zone
		(layer "F.Cu")
		(hatch none 0.5)
		(connect_pads
			(clearance 0)
		)
		(min_thickness 0.25)
		(keepout
			(tracks allowed)
			(vias allowed)
			(pads allowed)
			(copperpour allowed)
			(footprints allowed)
		)
		(placement
			(enabled no)
			(sheetname "")
		)
		(fill
			(thermal_gap 0.5)
			(thermal_bridge_width 0.5)
			(island_removal_mode 0)
		)
		(polygon
			(pts
				(xy 428.363126 -282.854908) (xy 428.363126 -282.626308) (xy 430.395126 -282.626308) (xy 430.395126 -282.854908)
			)
		)
	)
	(zone
		(layer "F.Cu")
		(hatch none 0.5)
		(connect_pads
			(clearance 0)
		)
		(min_thickness 0.25)
		(keepout
			(tracks allowed)
			(vias allowed)
			(pads allowed)
			(copperpour allowed)
			(footprints allowed)
		)
		(placement
			(enabled no)
			(sheetname "")
		)
		(fill
			(thermal_gap 0.5)
			(thermal_bridge_width 0.5)
			(island_removal_mode 0)
		)
		(polygon
			(pts
				(xy 235.62564 -135.059928) (xy 235.62564 -134.485888) (xy 238.01324 -134.485888) (xy 238.01324 -135.059928)
			)
		)
	)
	(zone
		(layer "F.Cu")
		(hatch none 0.5)
		(connect_pads
			(clearance 0)
		)
		(min_thickness 0.25)
		(keepout
			(tracks allowed)
			(vias allowed)
			(pads allowed)
			(copperpour allowed)
			(footprints allowed)
		)
		(placement
			(enabled no)
			(sheetname "")
		)
		(fill
			(thermal_gap 0.5)
			(thermal_bridge_width 0.5)
			(island_removal_mode 0)
		)
		(polygon
			(pts
				(xy 56.37911 -197.966584) (xy 56.37911 -197.522846) (xy 58.704226 -197.522846) (xy 58.704226 -197.966584)
			)
		)
	)
	(zone
		(layer "F.Cu")
		(hatch none 0.5)
		(connect_pads
			(clearance 0)
		)
		(min_thickness 0.25)
		(keepout
			(tracks allowed)
			(vias allowed)
			(pads allowed)
			(copperpour allowed)
			(footprints allowed)
		)
		(placement
			(enabled no)
			(sheetname "")
		)
		(fill
			(thermal_gap 0.5)
			(thermal_bridge_width 0.5)
			(island_removal_mode 0)
		)
		(polygon
			(pts
				(xy 176.979326 -235.026454) (xy 179.011326 -235.026454) (xy 179.011326 -235.255054) (xy 176.979326 -235.255054)
				(xy 176.843182 -235.255054) (xy 176.796192 -235.255054) (xy 176.796192 -235.026454) (xy 176.843182 -235.026454)
			)
		)
	)
	(zone
		(layer "F.Cu")
		(hatch none 0.5)
		(connect_pads
			(clearance 0)
		)
		(min_thickness 0.25)
		(keepout
			(tracks allowed)
			(vias allowed)
			(pads allowed)
			(copperpour allowed)
			(footprints allowed)
		)
		(placement
			(enabled no)
			(sheetname "")
		)
		(fill
			(thermal_gap 0.5)
			(thermal_bridge_width 0.5)
			(island_removal_mode 0)
		)
		(polygon
			(pts
				(xy 41.29151 -247.26646) (xy 41.29151 -246.822722) (xy 43.616626 -246.822722) (xy 43.616626 -247.26646)
			)
		)
	)
	(zone
		(layer "F.Cu")
		(hatch none 0.5)
		(connect_pads
			(clearance 0)
		)
		(min_thickness 0.25)
		(keepout
			(tracks allowed)
			(vias allowed)
			(pads allowed)
			(copperpour allowed)
			(footprints allowed)
		)
		(placement
			(enabled no)
			(sheetname "")
		)
		(fill
			(thermal_gap 0.5)
			(thermal_bridge_width 0.5)
			(island_removal_mode 0)
		)
		(polygon
			(pts
				(xy 86.57844 -324.696328) (xy 86.57844 -322.372228) (xy 91.03106 -322.372228) (xy 91.03106 -324.696328)
			)
		)
	)
	(zone
		(layer "F.Cu")
		(hatch none 0.5)
		(connect_pads
			(clearance 0)
		)
		(min_thickness 0.25)
		(keepout
			(tracks allowed)
			(vias allowed)
			(pads allowed)
			(copperpour allowed)
			(footprints allowed)
		)
		(placement
			(enabled no)
			(sheetname "")
		)
		(fill
			(thermal_gap 0.5)
			(thermal_bridge_width 0.5)
			(island_removal_mode 0)
		)
		(polygon
			(pts
				(xy 41.29151 -209.866484) (xy 41.29151 -209.422746) (xy 43.616626 -209.422746) (xy 43.616626 -209.866484)
			)
		)
	)
	(zone
		(layer "F.Cu")
		(hatch none 0.5)
		(connect_pads
			(clearance 0)
		)
		(min_thickness 0.25)
		(keepout
			(tracks allowed)
			(vias allowed)
			(pads allowed)
			(copperpour allowed)
			(footprints allowed)
		)
		(placement
			(enabled no)
			(sheetname "")
		)
		(fill
			(thermal_gap 0.5)
			(thermal_bridge_width 0.5)
			(island_removal_mode 0)
		)
		(polygon
			(pts
				(xy 381.60452 -288.999168) (xy 381.89154 -288.999168) (xy 381.92202 -288.968688) (xy 381.92202 -288.341308)
				(xy 381.83566 -288.254948) (xy 381.6477 -288.254948) (xy 381.57404 -288.328608) (xy 381.57404 -288.968688)
			)
		)
	)
	(zone
		(layer "F.Cu")
		(hatch none 0.5)
		(connect_pads
			(clearance 0)
		)
		(min_thickness 0.25)
		(keepout
			(tracks allowed)
			(vias allowed)
			(pads allowed)
			(copperpour allowed)
			(footprints allowed)
		)
		(placement
			(enabled no)
			(sheetname "")
		)
		(fill
			(thermal_gap 0.5)
			(thermal_bridge_width 0.5)
			(island_removal_mode 0)
		)
		(polygon
			(pts
				(xy 428.363126 -292.204902) (xy 428.363126 -291.976302) (xy 430.395126 -291.976302) (xy 430.395126 -292.204902)
			)
		)
	)
	(zone
		(layer "F.Cu")
		(hatch none 0.5)
		(connect_pads
			(clearance 0)
		)
		(min_thickness 0.25)
		(keepout
			(tracks allowed)
			(vias allowed)
			(pads allowed)
			(copperpour allowed)
			(footprints allowed)
		)
		(placement
			(enabled no)
			(sheetname "")
		)
		(fill
			(thermal_gap 0.5)
			(thermal_bridge_width 0.5)
			(island_removal_mode 0)
		)
		(polygon
			(pts
				(xy 180.423058 -289.654996) (xy 180.423058 -289.426396) (xy 182.455058 -289.426396) (xy 182.455058 -289.654996)
			)
		)
	)
	(zone
		(layer "F.Cu")
		(hatch none 0.5)
		(connect_pads
			(clearance 0)
		)
		(min_thickness 0.25)
		(keepout
			(tracks allowed)
			(vias allowed)
			(pads allowed)
			(copperpour allowed)
			(footprints not_allowed)
		)
		(placement
			(enabled no)
			(sheetname "")
		)
		(fill
			(thermal_gap 0.5)
			(thermal_bridge_width 0.5)
			(island_removal_mode 0)
		)
		(polygon
			(pts
				(arc
					(start 288.550096 -435.600094)
					(mid 293.550086 -430.600104)
					(end 298.550076 -435.600094)
				)
				(arc
					(start 298.550076 -435.600094)
					(mid 293.550086 -440.600084)
					(end 288.550096 -435.600094)
				)
			)
		)
	)
	(zone
		(layer "F.Cu")
		(hatch none 0.5)
		(connect_pads
			(clearance 0)
		)
		(min_thickness 0.25)
		(keepout
			(tracks allowed)
			(vias allowed)
			(pads allowed)
			(copperpour allowed)
			(footprints allowed)
		)
		(placement
			(enabled no)
			(sheetname "")
		)
		(fill
			(thermal_gap 0.5)
			(thermal_bridge_width 0.5)
			(island_removal_mode 0)
		)
		(polygon
			(pts
				(xy 157.791658 -316.004956) (xy 157.791658 -315.776356) (xy 159.823658 -315.776356) (xy 159.823658 -316.004956)
			)
		)
	)
	(zone
		(layer "F.Cu")
		(hatch none 0.5)
		(connect_pads
			(clearance 0)
		)
		(min_thickness 0.25)
		(keepout
			(tracks allowed)
			(vias allowed)
			(pads allowed)
			(copperpour allowed)
			(footprints allowed)
		)
		(placement
			(enabled no)
			(sheetname "")
		)
		(fill
			(thermal_gap 0.5)
			(thermal_bridge_width 0.5)
			(island_removal_mode 0)
		)
		(polygon
			(pts
				(xy 64.002412 -315.266578) (xy 64.002412 -314.82284) (xy 66.161412 -314.82284) (xy 66.161412 -315.266578)
			)
		)
	)
	(zone
		(layer "F.Cu")
		(hatch none 0.5)
		(connect_pads
			(clearance 0)
		)
		(min_thickness 0.25)
		(keepout
			(tracks allowed)
			(vias allowed)
			(pads allowed)
			(copperpour allowed)
			(footprints allowed)
		)
		(placement
			(enabled no)
			(sheetname "")
		)
		(fill
			(thermal_gap 0.5)
			(thermal_bridge_width 0.5)
			(island_removal_mode 0)
		)
		(polygon
			(pts
				(xy 44.735242 -198.816468) (xy 44.735242 -198.37273) (xy 47.060358 -198.37273) (xy 47.060358 -198.816468)
			)
		)
	)
	(zone
		(layer "F.Cu")
		(hatch none 0.5)
		(connect_pads
			(clearance 0)
		)
		(min_thickness 0.25)
		(keepout
			(tracks allowed)
			(vias allowed)
			(pads allowed)
			(copperpour allowed)
			(footprints allowed)
		)
		(placement
			(enabled no)
			(sheetname "")
		)
		(fill
			(thermal_gap 0.5)
			(thermal_bridge_width 0.5)
			(island_removal_mode 0)
		)
		(polygon
			(pts
				(xy 163.923726 -238.654844) (xy 161.891726 -238.654844) (xy 161.487612 -238.654844) (xy 161.487612 -237.584742)
				(xy 164.338508 -237.584742) (xy 164.338508 -238.654844)
			)
		)
	)
	(zone
		(layer "F.Cu")
		(hatch none 0.5)
		(connect_pads
			(clearance 0)
		)
		(min_thickness 0.25)
		(keepout
			(tracks allowed)
			(vias allowed)
			(pads allowed)
			(copperpour allowed)
			(footprints not_allowed)
		)
		(placement
			(enabled no)
			(sheetname "")
		)
		(fill
			(thermal_gap 0.5)
			(thermal_bridge_width 0.5)
			(island_removal_mode 0)
		)
		(polygon
			(pts
				(xy 323.864986 -348.836234) (xy 335.848706 -348.836234) (xy 335.848706 -345.424252)
				(arc
					(start 340.57971 -345.424252)
					(mid 341.498929 -345.043499)
					(end 341.879682 -344.12428)
				)
				(xy 341.879682 -339.691472) (xy 372.961662 -339.691472)
				(arc
					(start 372.961662 -344.12428)
					(mid 373.342415 -345.043499)
					(end 374.261634 -345.424252)
				)
				(xy 378.420884 -345.424252) (xy 378.420884 -348.836234) (xy 390.488678 -348.836234)
				(arc
					(start 390.488678 -340.51494)
					(mid 390.107925 -339.595721)
					(end 389.188706 -339.214968)
				)
				(xy 382.122172 -339.214968)
				(arc
					(start 382.122172 -334.724248)
					(mid 381.741419 -333.805029)
					(end 380.8222 -333.424276)
				)
				(xy 373.96166 -333.424276)
				(arc
					(start 373.96166 -331.314044)
					(mid 373.580907 -330.394825)
					(end 372.661688 -330.014072)
				)
				(arc
					(start 341.959184 -330.014072)
					(mid 341.039965 -330.394825)
					(end 340.659212 -331.314044)
				)
				(xy 340.659212 -333.424276)
				(arc
					(start 333.798672 -333.424276)
					(mid 332.879453 -333.805029)
					(end 332.4987 -334.724248)
				)
				(xy 332.4987 -339.214968)
				(arc
					(start 325.164958 -339.214968)
					(mid 324.245739 -339.595721)
					(end 323.864986 -340.51494)
				)
			)
		)
	)
	(zone
		(layer "F.Cu")
		(hatch none 0.5)
		(connect_pads
			(clearance 0)
		)
		(min_thickness 0.25)
		(keepout
			(tracks allowed)
			(vias allowed)
			(pads allowed)
			(copperpour allowed)
			(footprints allowed)
		)
		(placement
			(enabled no)
			(sheetname "")
		)
		(fill
			(thermal_gap 0.5)
			(thermal_bridge_width 0.5)
			(island_removal_mode 0)
		)
		(polygon
			(pts
				(xy 41.29151 -201.366628) (xy 41.29151 -200.92289) (xy 43.616626 -200.92289) (xy 43.616626 -201.366628)
			)
		)
	)
	(zone
		(layer "F.Cu")
		(hatch none 0.5)
		(connect_pads
			(clearance 0)
		)
		(min_thickness 0.25)
		(keepout
			(tracks allowed)
			(vias allowed)
			(pads allowed)
			(copperpour allowed)
			(footprints allowed)
		)
		(placement
			(enabled no)
			(sheetname "")
		)
		(fill
			(thermal_gap 0.5)
			(thermal_bridge_width 0.5)
			(island_removal_mode 0)
		)
		(polygon
			(pts
				(xy 292.67531 -226.86645) (xy 292.67531 -226.422712) (xy 295.000426 -226.422712) (xy 295.000426 -226.86645)
			)
		)
	)
	(zone
		(layer "F.Cu")
		(hatch none 0.5)
		(connect_pads
			(clearance 0)
		)
		(min_thickness 0.25)
		(keepout
			(tracks allowed)
			(vias allowed)
			(pads allowed)
			(copperpour allowed)
			(footprints allowed)
		)
		(placement
			(enabled no)
			(sheetname "")
		)
		(fill
			(thermal_gap 0.5)
			(thermal_bridge_width 0.5)
			(island_removal_mode 0)
		)
		(polygon
			(pts
				(xy 26.200862 -18.570702) (xy 26.200862 -15.436088) (xy 27.979624 -15.436088) (xy 27.979624 -18.570702)
			)
		)
	)
	(zone
		(layer "F.Cu")
		(hatch none 0.5)
		(connect_pads
			(clearance 0)
		)
		(min_thickness 0.25)
		(keepout
			(tracks not_allowed)
			(vias allowed)
			(pads allowed)
			(copperpour not_allowed)
			(footprints allowed)
		)
		(placement
			(enabled no)
			(sheetname "")
		)
		(fill
			(thermal_gap 0.5)
			(thermal_bridge_width 0.5)
			(island_removal_mode 0)
		)
		(polygon
			(pts
				(arc
					(start 456.000104 -435.600094)
					(mid 458.8002 -432.799998)
					(end 461.600042 -435.600094)
				)
				(arc
					(start 461.600042 -435.600094)
					(mid 458.8002 -438.399936)
					(end 456.000104 -435.600094)
				)
			)
		)
	)
	(zone
		(layer "F.Cu")
		(hatch none 0.5)
		(connect_pads
			(clearance 0)
		)
		(min_thickness 0.25)
		(keepout
			(tracks allowed)
			(vias allowed)
			(pads allowed)
			(copperpour allowed)
			(footprints allowed)
		)
		(placement
			(enabled no)
			(sheetname "")
		)
		(fill
			(thermal_gap 0.5)
			(thermal_bridge_width 0.5)
			(island_removal_mode 0)
		)
		(polygon
			(pts
				(xy 262.50011 -315.266578) (xy 262.50011 -314.82284) (xy 264.825226 -314.82284) (xy 264.825226 -315.266578)
			)
		)
	)
	(zone
		(layer "F.Cu")
		(hatch none 0.5)
		(connect_pads
			(clearance 0)
		)
		(min_thickness 0.25)
		(keepout
			(tracks allowed)
			(vias allowed)
			(pads allowed)
			(copperpour allowed)
			(footprints allowed)
		)
		(placement
			(enabled no)
			(sheetname "")
		)
		(fill
			(thermal_gap 0.5)
			(thermal_bridge_width 0.5)
			(island_removal_mode 0)
		)
		(polygon
			(pts
				(xy 207.154526 -209.75701) (xy 209.186526 -209.75701) (xy 209.186526 -209.52841) (xy 207.154526 -209.52841)
				(xy 207.023208 -209.52841) (xy 206.9973 -209.52841) (xy 206.9973 -209.75701) (xy 207.023208 -209.75701)
			)
		)
	)
	(zone
		(layer "F.Cu")
		(hatch none 0.5)
		(connect_pads
			(clearance 0)
		)
		(min_thickness 0.25)
		(keepout
			(tracks allowed)
			(vias allowed)
			(pads allowed)
			(copperpour allowed)
			(footprints allowed)
		)
		(placement
			(enabled no)
			(sheetname "")
		)
		(fill
			(thermal_gap 0.5)
			(thermal_bridge_width 0.5)
			(island_removal_mode 0)
		)
		(polygon
			(pts
				(xy 114.28222 -215.268048) (xy 114.56924 -215.268048) (xy 114.59972 -215.237568) (xy 114.59972 -214.610188)
				(xy 114.51336 -214.523828) (xy 114.3254 -214.523828) (xy 114.25174 -214.597488) (xy 114.25174 -215.237568)
			)
		)
	)
	(zone
		(layer "F.Cu")
		(hatch none 0.5)
		(connect_pads
			(clearance 0)
		)
		(min_thickness 0.25)
		(keepout
			(tracks allowed)
			(vias allowed)
			(pads allowed)
			(copperpour allowed)
			(footprints allowed)
		)
		(placement
			(enabled no)
			(sheetname "")
		)
		(fill
			(thermal_gap 0.5)
			(thermal_bridge_width 0.5)
			(island_removal_mode 0)
		)
		(polygon
			(pts
				(xy 383.01422 -288.166048) (xy 383.30124 -288.166048) (xy 383.33172 -288.135568) (xy 383.33172 -287.508188)
				(xy 383.24536 -287.421828) (xy 383.0574 -287.421828) (xy 382.98374 -287.495488) (xy 382.98374 -288.135568)
			)
		)
	)
	(zone
		(layer "F.Cu")
		(hatch none 0.5)
		(connect_pads
			(clearance 0)
		)
		(min_thickness 0.25)
		(keepout
			(tracks allowed)
			(vias allowed)
			(pads allowed)
			(copperpour allowed)
			(footprints not_allowed)
		)
		(placement
			(enabled no)
			(sheetname "")
		)
		(fill
			(thermal_gap 0.5)
			(thermal_bridge_width 0.5)
			(island_removal_mode 0)
		)
		(polygon
			(pts
				(arc
					(start 92.099892 -22.29993)
					(mid 94.899988 -19.499834)
					(end 97.700084 -22.29993)
				)
				(arc
					(start 97.700084 -22.29993)
					(mid 94.899988 -25.100026)
					(end 92.099892 -22.29993)
				)
			)
		)
	)
	(zone
		(layer "F.Cu")
		(hatch none 0.5)
		(connect_pads
			(clearance 0)
		)
		(min_thickness 0.25)
		(keepout
			(tracks allowed)
			(vias allowed)
			(pads allowed)
			(copperpour allowed)
			(footprints allowed)
		)
		(placement
			(enabled no)
			(sheetname "")
		)
		(fill
			(thermal_gap 0.5)
			(thermal_bridge_width 0.5)
			(island_removal_mode 0)
		)
		(polygon
			(pts
				(xy 207.154526 -219.726256) (xy 209.186526 -219.726256) (xy 209.186526 -219.954856) (xy 207.154526 -219.954856)
				(xy 207.023208 -219.954856) (xy 206.9973 -219.954856) (xy 206.9973 -219.726256) (xy 207.023208 -219.726256)
			)
		)
	)
	(zone
		(layer "F.Cu")
		(hatch none 0.5)
		(connect_pads
			(clearance 0)
		)
		(min_thickness 0.25)
		(keepout
			(tracks allowed)
			(vias allowed)
			(pads allowed)
			(copperpour allowed)
			(footprints allowed)
		)
		(placement
			(enabled no)
			(sheetname "")
		)
		(fill
			(thermal_gap 0.5)
			(thermal_bridge_width 0.5)
			(island_removal_mode 0)
		)
		(polygon
			(pts
				(xy 440.006994 -211.2264) (xy 442.038994 -211.2264) (xy 442.038994 -211.455) (xy 440.006994 -211.455)
				(xy 439.87085 -211.455) (xy 439.82386 -211.455) (xy 439.82386 -211.2264) (xy 439.87085 -211.2264)
			)
		)
	)
	(zone
		(layer "F.Cu")
		(hatch none 0.5)
		(connect_pads
			(clearance 0)
		)
		(min_thickness 0.25)
		(keepout
			(tracks allowed)
			(vias allowed)
			(pads allowed)
			(copperpour allowed)
			(footprints allowed)
		)
		(placement
			(enabled no)
			(sheetname "")
		)
		(fill
			(thermal_gap 0.5)
			(thermal_bridge_width 0.5)
			(island_removal_mode 0)
		)
		(polygon
			(pts
				(xy 11.11631 -197.966584) (xy 11.11631 -197.522846) (xy 13.441426 -197.522846) (xy 13.441426 -197.966584)
			)
		)
	)
	(zone
		(layer "F.Cu")
		(hatch none 0.5)
		(connect_pads
			(clearance 0)
		)
		(min_thickness 0.25)
		(keepout
			(tracks allowed)
			(vias allowed)
			(pads allowed)
			(copperpour allowed)
			(footprints allowed)
		)
		(placement
			(enabled no)
			(sheetname "")
		)
		(fill
			(thermal_gap 0.5)
			(thermal_bridge_width 0.5)
			(island_removal_mode 0)
		)
		(polygon
			(pts
				(xy 180.423058 -272.65503) (xy 180.423058 -272.42643) (xy 182.455058 -272.42643) (xy 182.455058 -272.65503)
			)
		)
	)
	(zone
		(layer "F.Cu")
		(hatch none 0.5)
		(connect_pads
			(clearance 0)
		)
		(min_thickness 0.25)
		(keepout
			(tracks allowed)
			(vias allowed)
			(pads allowed)
			(copperpour allowed)
			(footprints allowed)
		)
		(placement
			(enabled no)
			(sheetname "")
		)
		(fill
			(thermal_gap 0.5)
			(thermal_bridge_width 0.5)
			(island_removal_mode 0)
		)
		(polygon
			(pts
				(xy 157.791658 -216.554812) (xy 157.791658 -216.326212) (xy 159.823658 -216.326212) (xy 159.823658 -216.554812)
			)
		)
	)
	(zone
		(layer "F.Cu")
		(hatch none 0.5)
		(connect_pads
			(clearance 0)
		)
		(min_thickness 0.25)
		(keepout
			(tracks allowed)
			(vias allowed)
			(pads allowed)
			(copperpour allowed)
			(footprints allowed)
		)
		(placement
			(enabled no)
			(sheetname "")
		)
		(fill
			(thermal_gap 0.5)
			(thermal_bridge_width 0.5)
			(island_removal_mode 0)
		)
		(polygon
			(pts
				(xy 409.133548 -20.04822) (xy 409.133548 -16.913606) (xy 410.91231 -16.913606) (xy 410.91231 -20.04822)
			)
		)
	)
	(zone
		(layer "F.Cu")
		(hatch none 0.5)
		(connect_pads
			(clearance 0)
		)
		(min_thickness 0.25)
		(keepout
			(tracks allowed)
			(vias allowed)
			(pads allowed)
			(copperpour allowed)
			(footprints allowed)
		)
		(placement
			(enabled no)
			(sheetname "")
		)
		(fill
			(thermal_gap 0.5)
			(thermal_bridge_width 0.5)
			(island_removal_mode 0)
		)
		(polygon
			(pts
				(xy 405.731726 -252.25502) (xy 405.731726 -252.02642) (xy 407.763726 -252.02642) (xy 407.763726 -252.25502)
			)
		)
	)
	(zone
		(layer "F.Cu")
		(hatch none 0.5)
		(connect_pads
			(clearance 0)
		)
		(min_thickness 0.25)
		(keepout
			(tracks allowed)
			(vias allowed)
			(pads allowed)
			(copperpour allowed)
			(footprints allowed)
		)
		(placement
			(enabled no)
			(sheetname "")
		)
		(fill
			(thermal_gap 0.5)
			(thermal_bridge_width 0.5)
			(island_removal_mode 0)
		)
		(polygon
			(pts
				(xy 11.11631 -235.36656) (xy 11.11631 -234.922822) (xy 13.441426 -234.922822) (xy 13.441426 -235.36656)
			)
		)
	)
	(zone
		(layer "F.Cu")
		(hatch none 0.5)
		(connect_pads
			(clearance 0)
		)
		(min_thickness 0.25)
		(keepout
			(tracks allowed)
			(vias allowed)
			(pads allowed)
			(copperpour allowed)
			(footprints allowed)
		)
		(placement
			(enabled no)
			(sheetname "")
		)
		(fill
			(thermal_gap 0.5)
			(thermal_bridge_width 0.5)
			(island_removal_mode 0)
		)
		(polygon
			(pts
				(xy 286.253174 -360.748834) (xy 286.253174 -364.754414) (xy 286.733234 -365.234474) (xy 288.798254 -365.234474)
				(xy 289.070034 -364.962694) (xy 289.070034 -363.108494) (xy 289.321494 -362.857034) (xy 291.241734 -362.857034)
				(xy 291.658294 -362.440474) (xy 291.658294 -360.949494) (xy 291.010594 -360.301794) (xy 286.700214 -360.301794)
			)
		)
	)
	(zone
		(layer "F.Cu")
		(hatch none 0.5)
		(connect_pads
			(clearance 0)
		)
		(min_thickness 0.25)
		(keepout
			(tracks allowed)
			(vias allowed)
			(pads allowed)
			(copperpour allowed)
			(footprints allowed)
		)
		(placement
			(enabled no)
			(sheetname "")
		)
		(fill
			(thermal_gap 0.5)
			(thermal_bridge_width 0.5)
			(island_removal_mode 0)
		)
		(polygon
			(pts
				(xy 413.275526 -222.505016) (xy 413.275526 -222.276416) (xy 415.307526 -222.276416) (xy 415.307526 -222.505016)
			)
		)
	)
	(zone
		(layer "F.Cu")
		(hatch none 0.5)
		(connect_pads
			(clearance 0)
		)
		(min_thickness 0.25)
		(keepout
			(tracks allowed)
			(vias allowed)
			(pads allowed)
			(copperpour allowed)
			(footprints allowed)
		)
		(placement
			(enabled no)
			(sheetname "")
		)
		(fill
			(thermal_gap 0.5)
			(thermal_bridge_width 0.5)
			(island_removal_mode 0)
		)
		(polygon
			(pts
				(xy 428.363126 -310.055006) (xy 428.363126 -309.826406) (xy 430.395126 -309.826406) (xy 430.395126 -310.055006)
			)
		)
	)
	(zone
		(layer "F.Cu")
		(hatch none 0.5)
		(connect_pads
			(clearance 0)
		)
		(min_thickness 0.25)
		(keepout
			(tracks allowed)
			(vias allowed)
			(pads allowed)
			(copperpour allowed)
			(footprints allowed)
		)
		(placement
			(enabled no)
			(sheetname "")
		)
		(fill
			(thermal_gap 0.5)
			(thermal_bridge_width 0.5)
			(island_removal_mode 0)
		)
		(polygon
			(pts
				(xy 292.67531 -292.316662) (xy 292.67531 -291.872924) (xy 295.000426 -291.872924) (xy 295.000426 -292.316662)
			)
		)
	)
	(zone
		(layer "F.Cu")
		(hatch none 0.5)
		(connect_pads
			(clearance 0)
		)
		(min_thickness 0.25)
		(keepout
			(tracks allowed)
			(vias allowed)
			(pads allowed)
			(copperpour allowed)
			(footprints not_allowed)
		)
		(placement
			(enabled no)
			(sheetname "")
		)
		(fill
			(thermal_gap 0.5)
			(thermal_bridge_width 0.5)
			(island_removal_mode 0)
		)
		(polygon
			(pts
				(xy 423.399966 -47.764954) (xy 432.399948 -47.764954) (xy 432.399948 -26.234898) (xy 423.399966 -26.234898)
			)
		)
	)
	(zone
		(layer "F.Cu")
		(hatch none 0.5)
		(connect_pads
			(clearance 0)
		)
		(min_thickness 0.25)
		(keepout
			(tracks allowed)
			(vias allowed)
			(pads allowed)
			(copperpour allowed)
			(footprints allowed)
		)
		(placement
			(enabled no)
			(sheetname "")
		)
		(fill
			(thermal_gap 0.5)
			(thermal_bridge_width 0.5)
			(island_removal_mode 0)
		)
		(polygon
			(pts
				(xy 458.538326 -311.755028) (xy 458.538326 -311.526428) (xy 460.570326 -311.526428) (xy 460.570326 -311.755028)
			)
		)
	)
	(zone
		(layer "F.Cu")
		(hatch none 0.5)
		(connect_pads
			(clearance 0)
		)
		(min_thickness 0.25)
		(keepout
			(tracks allowed)
			(vias allowed)
			(pads allowed)
			(copperpour allowed)
			(footprints allowed)
		)
		(placement
			(enabled no)
			(sheetname "")
		)
		(fill
			(thermal_gap 0.5)
			(thermal_bridge_width 0.5)
			(island_removal_mode 0)
		)
		(polygon
			(pts
				(xy 311.89168 -297.416474) (xy 311.89168 -296.972736) (xy 314.10148 -296.972736) (xy 314.10148 -297.416474)
			)
		)
	)
	(zone
		(layer "F.Cu")
		(hatch none 0.5)
		(connect_pads
			(clearance 0)
		)
		(min_thickness 0.25)
		(keepout
			(tracks allowed)
			(vias allowed)
			(pads allowed)
			(copperpour allowed)
			(footprints allowed)
		)
		(placement
			(enabled no)
			(sheetname "")
		)
		(fill
			(thermal_gap 0.5)
			(thermal_bridge_width 0.5)
			(island_removal_mode 0)
		)
		(polygon
			(pts
				(xy 413.275526 -226.754944) (xy 413.275526 -226.526344) (xy 415.307526 -226.526344) (xy 415.307526 -226.754944)
			)
		)
	)
	(zone
		(layer "F.Cu")
		(hatch none 0.5)
		(connect_pads
			(clearance 0)
		)
		(min_thickness 0.25)
		(keepout
			(tracks allowed)
			(vias allowed)
			(pads allowed)
			(copperpour allowed)
			(footprints allowed)
		)
		(placement
			(enabled no)
			(sheetname "")
		)
		(fill
			(thermal_gap 0.5)
			(thermal_bridge_width 0.5)
			(island_removal_mode 0)
		)
		(polygon
			(pts
				(xy 91.754452 -410.948886) (xy 91.754452 -406.105868) (xy 93.638878 -406.105868) (xy 93.638878 -410.948886)
			)
		)
	)
	(zone
		(layer "F.Cu")
		(hatch none 0.5)
		(connect_pads
			(clearance 0)
		)
		(min_thickness 0.25)
		(keepout
			(tracks allowed)
			(vias allowed)
			(pads allowed)
			(copperpour allowed)
			(footprints allowed)
		)
		(placement
			(enabled no)
			(sheetname "")
		)
		(fill
			(thermal_gap 0.5)
			(thermal_bridge_width 0.5)
			(island_removal_mode 0)
		)
		(polygon
			(pts
				(xy 405.731726 -292.204902) (xy 405.731726 -291.976302) (xy 407.763726 -291.976302) (xy 407.763726 -292.204902)
			)
		)
	)
	(zone
		(layer "F.Cu")
		(hatch none 0.5)
		(connect_pads
			(clearance 0)
		)
		(min_thickness 0.25)
		(keepout
			(tracks allowed)
			(vias allowed)
			(pads allowed)
			(copperpour allowed)
			(footprints allowed)
		)
		(placement
			(enabled no)
			(sheetname "")
		)
		(fill
			(thermal_gap 0.5)
			(thermal_bridge_width 0.5)
			(island_removal_mode 0)
		)
		(polygon
			(pts
				(xy 210.598258 -218.254834) (xy 210.598258 -218.026234) (xy 212.630258 -218.026234) (xy 212.630258 -218.254834)
			)
		)
	)
	(zone
		(layer "F.Cu")
		(hatch none 0.5)
		(connect_pads
			(clearance 0)
		)
		(min_thickness 0.25)
		(keepout
			(tracks allowed)
			(vias allowed)
			(pads allowed)
			(copperpour allowed)
			(footprints allowed)
		)
		(placement
			(enabled no)
			(sheetname "")
		)
		(fill
			(thermal_gap 0.5)
			(thermal_bridge_width 0.5)
			(island_removal_mode 0)
		)
		(polygon
			(pts
				(xy 192.066926 -229.926388) (xy 194.098926 -229.926388) (xy 194.098926 -230.154988) (xy 192.066926 -230.154988)
				(xy 191.930782 -230.154988) (xy 191.883792 -230.154988) (xy 191.883792 -229.926388) (xy 191.930782 -229.926388)
			)
		)
	)
	(zone
		(layer "F.Cu")
		(hatch none 0.5)
		(connect_pads
			(clearance 0)
		)
		(min_thickness 0.25)
		(keepout
			(tracks allowed)
			(vias allowed)
			(pads allowed)
			(copperpour allowed)
			(footprints allowed)
		)
		(placement
			(enabled no)
			(sheetname "")
		)
		(fill
			(thermal_gap 0.5)
			(thermal_bridge_width 0.5)
			(island_removal_mode 0)
		)
		(polygon
			(pts
				(xy 158.58998 -45.085508) (xy 158.58998 -43.020488) (xy 160.64484 -43.020488) (xy 160.64484 -45.085508)
			)
		)
	)
	(zone
		(layer "F.Cu")
		(hatch none 0.5)
		(connect_pads
			(clearance 0)
		)
		(min_thickness 0.25)
		(keepout
			(tracks allowed)
			(vias allowed)
			(pads allowed)
			(copperpour allowed)
			(footprints allowed)
		)
		(placement
			(enabled no)
			(sheetname "")
		)
		(fill
			(thermal_gap 0.5)
			(thermal_bridge_width 0.5)
			(island_removal_mode 0)
		)
		(polygon
			(pts
				(xy 75.092052 -404.802594) (xy 75.092052 -399.959576) (xy 76.976478 -399.959576) (xy 76.976478 -404.802594)
			)
		)
	)
	(zone
		(layer "F.Cu")
		(hatch none 0.5)
		(connect_pads
			(clearance 0)
		)
		(min_thickness 0.25)
		(keepout
			(tracks allowed)
			(vias allowed)
			(pads allowed)
			(copperpour allowed)
			(footprints allowed)
		)
		(placement
			(enabled no)
			(sheetname "")
		)
		(fill
			(thermal_gap 0.5)
			(thermal_bridge_width 0.5)
			(island_removal_mode 0)
		)
		(polygon
			(pts
				(xy 440.006994 -276.676358) (xy 442.038994 -276.676358) (xy 442.038994 -276.678644) (xy 442.21781 -276.678644)
				(xy 442.21781 -276.91588) (xy 442.355732 -276.91588) (xy 442.398912 -276.95906) (xy 442.398912 -277.091902)
				(xy 442.398912 -277.39594) (xy 442.326268 -277.468584) (xy 439.786014 -277.468584) (xy 439.64479 -277.32736)
				(xy 439.64479 -277.130256) (xy 439.726324 -277.048722) (xy 439.726324 -276.676358) (xy 439.82386 -276.676358)
				(xy 439.87085 -276.676358)
			)
		)
	)
	(zone
		(layer "F.Cu")
		(hatch none 0.5)
		(connect_pads
			(clearance 0)
		)
		(min_thickness 0.25)
		(keepout
			(tracks allowed)
			(vias allowed)
			(pads allowed)
			(copperpour allowed)
			(footprints allowed)
		)
		(placement
			(enabled no)
			(sheetname "")
		)
		(fill
			(thermal_gap 0.5)
			(thermal_bridge_width 0.5)
			(island_removal_mode 0)
		)
		(polygon
			(pts
				(xy 259.056378 -209.866484) (xy 259.056378 -209.422746) (xy 261.381494 -209.422746) (xy 261.381494 -209.866484)
			)
		)
	)
	(zone
		(layer "F.Cu")
		(hatch none 0.5)
		(connect_pads
			(clearance 0)
		)
		(min_thickness 0.25)
		(keepout
			(tracks allowed)
			(vias allowed)
			(pads allowed)
			(copperpour allowed)
			(footprints allowed)
		)
		(placement
			(enabled no)
			(sheetname "")
		)
		(fill
			(thermal_gap 0.5)
			(thermal_bridge_width 0.5)
			(island_removal_mode 0)
		)
		(polygon
			(pts
				(xy 59.822842 -287.216596) (xy 59.822842 -286.772858) (xy 62.147958 -286.772858) (xy 62.147958 -287.216596)
			)
		)
	)
	(zone
		(layer "F.Cu")
		(hatch none 0.5)
		(connect_pads
			(clearance 0)
		)
		(min_thickness 0.25)
		(keepout
			(tracks allowed)
			(vias allowed)
			(pads allowed)
			(copperpour allowed)
			(footprints allowed)
		)
		(placement
			(enabled no)
			(sheetname "")
		)
		(fill
			(thermal_gap 0.5)
			(thermal_bridge_width 0.5)
			(island_removal_mode 0)
		)
		(polygon
			(pts
				(xy 53.83657 -173.34611) (xy 53.83657 -171.53001) (xy 55.21579 -171.53001) (xy 55.21579 -173.34611)
			)
		)
	)
	(zone
		(layer "F.Cu")
		(hatch none 0.5)
		(connect_pads
			(clearance 0)
		)
		(min_thickness 0.25)
		(keepout
			(tracks allowed)
			(vias allowed)
			(pads allowed)
			(copperpour allowed)
			(footprints not_allowed)
		)
		(placement
			(enabled no)
			(sheetname "")
		)
		(fill
			(thermal_gap 0.5)
			(thermal_bridge_width 0.5)
			(island_removal_mode 0)
		)
		(polygon
			(pts
				(arc
					(start 228.650038 -352.49993)
					(mid 236.650022 -344.499946)
					(end 244.650006 -352.49993)
				)
				(arc
					(start 244.650006 -352.49993)
					(mid 236.650022 -360.499914)
					(end 228.650038 -352.49993)
				)
			)
		)
	)
	(zone
		(layer "F.Cu")
		(hatch none 0.5)
		(connect_pads
			(clearance 0)
		)
		(min_thickness 0.25)
		(keepout
			(tracks allowed)
			(vias allowed)
			(pads allowed)
			(copperpour allowed)
			(footprints allowed)
		)
		(placement
			(enabled no)
			(sheetname "")
		)
		(fill
			(thermal_gap 0.5)
			(thermal_bridge_width 0.5)
			(island_removal_mode 0)
		)
		(polygon
			(pts
				(xy 195.510658 -287.954974) (xy 195.510658 -287.726374) (xy 197.542658 -287.726374) (xy 197.542658 -287.954974)
			)
		)
	)
	(zone
		(layer "F.Cu")
		(hatch none 0.5)
		(connect_pads
			(clearance 0)
		)
		(min_thickness 0.25)
		(keepout
			(tracks allowed)
			(vias allowed)
			(pads allowed)
			(copperpour allowed)
			(footprints allowed)
		)
		(placement
			(enabled no)
			(sheetname "")
		)
		(fill
			(thermal_gap 0.5)
			(thermal_bridge_width 0.5)
			(island_removal_mode 0)
		)
		(polygon
			(pts
				(xy 11.11631 -247.26646) (xy 11.11631 -246.822722) (xy 13.441426 -246.822722) (xy 13.441426 -247.26646)
			)
		)
	)
	(zone
		(layer "F.Cu")
		(hatch none 0.5)
		(connect_pads
			(clearance 0)
		)
		(min_thickness 0.25)
		(keepout
			(tracks allowed)
			(vias allowed)
			(pads allowed)
			(copperpour allowed)
			(footprints allowed)
		)
		(placement
			(enabled no)
			(sheetname "")
		)
		(fill
			(thermal_gap 0.5)
			(thermal_bridge_width 0.5)
			(island_removal_mode 0)
		)
		(polygon
			(pts
				(xy 84.173822 -232.582466) (xy 84.376768 -232.785412) (xy 84.419948 -232.785412) (xy 84.863686 -232.341674)
				(xy 84.863686 -232.2195) (xy 84.73059 -232.086658) (xy 84.62645 -232.086658) (xy 84.173822 -232.539286)
			)
		)
	)
	(zone
		(layer "F.Cu")
		(hatch none 0.5)
		(connect_pads
			(clearance 0)
		)
		(min_thickness 0.25)
		(keepout
			(tracks allowed)
			(vias allowed)
			(pads allowed)
			(copperpour allowed)
			(footprints allowed)
		)
		(placement
			(enabled no)
			(sheetname "")
		)
		(fill
			(thermal_gap 0.5)
			(thermal_bridge_width 0.5)
			(island_removal_mode 0)
		)
		(polygon
			(pts
				(xy 405.731726 -198.704962) (xy 405.731726 -198.476362) (xy 407.763726 -198.476362) (xy 407.763726 -198.704962)
			)
		)
	)
	(zone
		(layer "F.Cu")
		(hatch none 0.5)
		(connect_pads
			(clearance 0)
		)
		(min_thickness 0.25)
		(keepout
			(tracks allowed)
			(vias allowed)
			(pads allowed)
			(copperpour allowed)
			(footprints allowed)
		)
		(placement
			(enabled no)
			(sheetname "")
		)
		(fill
			(thermal_gap 0.5)
			(thermal_bridge_width 0.5)
			(island_removal_mode 0)
		)
		(polygon
			(pts
				(xy 418.512752 -150.430738) (xy 418.512752 -153.966418) (xy 416.429952 -153.966418) (xy 416.429952 -150.430738)
			)
		)
	)
	(zone
		(layer "F.Cu")
		(hatch none 0.5)
		(connect_pads
			(clearance 0)
		)
		(min_thickness 0.25)
		(keepout
			(tracks allowed)
			(vias allowed)
			(pads allowed)
			(copperpour allowed)
			(footprints allowed)
		)
		(placement
			(enabled no)
			(sheetname "")
		)
		(fill
			(thermal_gap 0.5)
			(thermal_bridge_width 0.5)
			(island_removal_mode 0)
		)
		(polygon
			(pts
				(xy 246.4435 -92.964508) (xy 246.4435 -89.339928) (xy 250.39828 -89.339928) (xy 250.39828 -92.964508)
			)
		)
	)
	(zone
		(layer "F.Cu")
		(hatch none 0.5)
		(connect_pads
			(clearance 0)
		)
		(min_thickness 0.25)
		(keepout
			(tracks allowed)
			(vias allowed)
			(pads allowed)
			(copperpour allowed)
			(footprints allowed)
		)
		(placement
			(enabled no)
			(sheetname "")
		)
		(fill
			(thermal_gap 0.5)
			(thermal_bridge_width 0.5)
			(island_removal_mode 0)
		)
		(polygon
			(pts
				(xy 192.066926 -235.026454) (xy 194.098926 -235.026454) (xy 194.098926 -235.02874) (xy 194.277742 -235.02874)
				(xy 194.277742 -235.265976) (xy 194.415664 -235.265976) (xy 194.458844 -235.309156) (xy 194.458844 -235.441998)
				(xy 194.458844 -235.746036) (xy 194.3862 -235.81868) (xy 191.845946 -235.81868) (xy 191.704722 -235.677456)
				(xy 191.704722 -235.480352) (xy 191.786256 -235.398818) (xy 191.786256 -235.026454) (xy 191.883792 -235.026454)
				(xy 191.930782 -235.026454)
			)
		)
	)
	(zone
		(layer "F.Cu")
		(hatch none 0.5)
		(connect_pads
			(clearance 0)
		)
		(min_thickness 0.25)
		(keepout
			(tracks allowed)
			(vias allowed)
			(pads allowed)
			(copperpour allowed)
			(footprints allowed)
		)
		(placement
			(enabled no)
			(sheetname "")
		)
		(fill
			(thermal_gap 0.5)
			(thermal_bridge_width 0.5)
			(island_removal_mode 0)
		)
		(polygon
			(pts
				(xy 458.538326 -295.604946) (xy 458.538326 -295.376346) (xy 460.570326 -295.376346) (xy 460.570326 -295.604946)
			)
		)
	)
	(zone
		(layer "F.Cu")
		(hatch none 0.5)
		(connect_pads
			(clearance 0)
		)
		(min_thickness 0.25)
		(keepout
			(tracks allowed)
			(vias allowed)
			(pads allowed)
			(copperpour allowed)
			(footprints allowed)
		)
		(placement
			(enabled no)
			(sheetname "")
		)
		(fill
			(thermal_gap 0.5)
			(thermal_bridge_width 0.5)
			(island_removal_mode 0)
		)
		(polygon
			(pts
				(xy 59.822842 -213.266528) (xy 59.822842 -212.82279) (xy 62.147958 -212.82279) (xy 62.147958 -213.266528)
			)
		)
	)
	(zone
		(layer "F.Cu")
		(hatch none 0.5)
		(connect_pads
			(clearance 0)
		)
		(min_thickness 0.25)
		(keepout
			(tracks allowed)
			(vias allowed)
			(pads allowed)
			(copperpour allowed)
			(footprints allowed)
		)
		(placement
			(enabled no)
			(sheetname "")
		)
		(fill
			(thermal_gap 0.5)
			(thermal_bridge_width 0.5)
			(island_removal_mode 0)
		)
		(polygon
			(pts
				(xy 11.11631 -286.366458) (xy 11.11631 -285.92272) (xy 13.441426 -285.92272) (xy 13.441426 -286.366458)
			)
		)
	)
	(zone
		(layer "F.Cu")
		(hatch none 0.5)
		(connect_pads
			(clearance 0)
		)
		(min_thickness 0.25)
		(keepout
			(tracks allowed)
			(vias allowed)
			(pads allowed)
			(copperpour allowed)
			(footprints allowed)
		)
		(placement
			(enabled no)
			(sheetname "")
		)
		(fill
			(thermal_gap 0.5)
			(thermal_bridge_width 0.5)
			(island_removal_mode 0)
		)
		(polygon
			(pts
				(xy 386.373116 -272.079212) (xy 386.576062 -272.282158) (xy 386.618988 -272.282158) (xy 387.062726 -271.838674)
				(xy 387.062726 -271.7165) (xy 386.929884 -271.583404) (xy 386.825744 -271.583404) (xy 386.373116 -272.036032)
			)
		)
	)
	(zone
		(layer "F.Cu")
		(hatch none 0.5)
		(connect_pads
			(clearance 0)
		)
		(min_thickness 0.25)
		(keepout
			(tracks allowed)
			(vias allowed)
			(pads allowed)
			(copperpour allowed)
			(footprints allowed)
		)
		(placement
			(enabled no)
			(sheetname "")
		)
		(fill
			(thermal_gap 0.5)
			(thermal_bridge_width 0.5)
			(island_removal_mode 0)
		)
		(polygon
			(pts
				(xy 455.094594 -303.876202) (xy 457.126594 -303.876202) (xy 457.126594 -304.104802) (xy 455.094594 -304.104802)
				(xy 454.963276 -304.104802) (xy 454.937368 -304.104802) (xy 454.937368 -303.876202) (xy 454.963276 -303.876202)
			)
		)
	)
	(zone
		(layer "F.Cu")
		(hatch none 0.5)
		(connect_pads
			(clearance 0)
		)
		(min_thickness 0.25)
		(keepout
			(tracks not_allowed)
			(vias allowed)
			(pads allowed)
			(copperpour not_allowed)
			(footprints allowed)
		)
		(placement
			(enabled no)
			(sheetname "")
		)
		(fill
			(thermal_gap 0.5)
			(thermal_bridge_width 0.5)
			(island_removal_mode 0)
		)
		(polygon
			(pts
				(arc
					(start 385.899914 -22.29993)
					(mid 380.899924 -27.29992)
					(end 375.899934 -22.29993)
				)
				(arc
					(start 375.899934 -22.29993)
					(mid 380.899924 -17.29994)
					(end 385.899914 -22.29993)
				)
			)
		)
	)
	(zone
		(layer "F.Cu")
		(hatch none 0.5)
		(connect_pads
			(clearance 0)
		)
		(min_thickness 0.25)
		(keepout
			(tracks allowed)
			(vias allowed)
			(pads allowed)
			(copperpour allowed)
			(footprints allowed)
		)
		(placement
			(enabled no)
			(sheetname "")
		)
		(fill
			(thermal_gap 0.5)
			(thermal_bridge_width 0.5)
			(island_removal_mode 0)
		)
		(polygon
			(pts
				(xy 405.731726 -218.254834) (xy 405.731726 -218.026234) (xy 407.763726 -218.026234) (xy 407.763726 -218.254834)
			)
		)
	)
	(zone
		(layer "F.Cu")
		(hatch none 0.5)
		(connect_pads
			(clearance 0)
		)
		(min_thickness 0.25)
		(keepout
			(tracks allowed)
			(vias allowed)
			(pads allowed)
			(copperpour allowed)
			(footprints allowed)
		)
		(placement
			(enabled no)
			(sheetname "")
		)
		(fill
			(thermal_gap 0.5)
			(thermal_bridge_width 0.5)
			(island_removal_mode 0)
		)
		(polygon
			(pts
				(xy 11.11631 -260.866636) (xy 11.11631 -260.422898) (xy 13.441426 -260.422898) (xy 13.441426 -260.866636)
			)
		)
	)
	(zone
		(layer "F.Cu")
		(hatch none 0.5)
		(connect_pads
			(clearance 0)
		)
		(min_thickness 0.25)
		(keepout
			(tracks allowed)
			(vias allowed)
			(pads allowed)
			(copperpour allowed)
			(footprints allowed)
		)
		(placement
			(enabled no)
			(sheetname "")
		)
		(fill
			(thermal_gap 0.5)
			(thermal_bridge_width 0.5)
			(island_removal_mode 0)
		)
		(polygon
			(pts
				(xy 307.76291 -226.016566) (xy 307.76291 -225.572828) (xy 310.088026 -225.572828) (xy 310.088026 -226.016566)
			)
		)
	)
	(zone
		(layer "F.Cu")
		(hatch none 0.5)
		(connect_pads
			(clearance 0)
		)
		(min_thickness 0.25)
		(keepout
			(tracks allowed)
			(vias allowed)
			(pads allowed)
			(copperpour allowed)
			(footprints not_allowed)
		)
		(placement
			(enabled no)
			(sheetname "")
		)
		(fill
			(thermal_gap 0.5)
			(thermal_bridge_width 0.5)
			(island_removal_mode 0)
		)
		(polygon
			(pts
				(arc
					(start 270.649954 -22.29993)
					(mid 270.495247 -23.534337)
					(end 270.040608 -24.692356)
				)
				(xy 270.040608 -46.150022) (xy 295.900094 -46.150022) (xy 295.900094 -21.850096)
				(arc
					(start 270.629634 -21.850096)
					(mid 270.644867 -22.074784)
					(end 270.649954 -22.29993)
				)
			)
		)
	)
	(zone
		(layer "F.Cu")
		(hatch none 0.5)
		(connect_pads
			(clearance 0)
		)
		(min_thickness 0.25)
		(keepout
			(tracks allowed)
			(vias allowed)
			(pads allowed)
			(copperpour allowed)
			(footprints allowed)
		)
		(placement
			(enabled no)
			(sheetname "")
		)
		(fill
			(thermal_gap 0.5)
			(thermal_bridge_width 0.5)
			(island_removal_mode 0)
		)
		(polygon
			(pts
				(xy 210.598258 -230.154988) (xy 210.598258 -229.926388) (xy 212.630258 -229.926388) (xy 212.630258 -230.154988)
			)
		)
	)
	(zone
		(layer "F.Cu")
		(hatch none 0.5)
		(connect_pads
			(clearance 0)
		)
		(min_thickness 0.25)
		(keepout
			(tracks allowed)
			(vias allowed)
			(pads allowed)
			(copperpour allowed)
			(footprints allowed)
		)
		(placement
			(enabled no)
			(sheetname "")
		)
		(fill
			(thermal_gap 0.5)
			(thermal_bridge_width 0.5)
			(island_removal_mode 0)
		)
		(polygon
			(pts
				(xy 105.149904 -335.958942) (xy 103.402384 -335.958942) (xy 103.402384 -334.023462) (xy 105.149904 -334.023462)
			)
		)
	)
	(zone
		(layer "F.Cu")
		(hatch none 0.5)
		(connect_pads
			(clearance 0)
		)
		(min_thickness 0.25)
		(keepout
			(tracks allowed)
			(vias allowed)
			(pads allowed)
			(copperpour allowed)
			(footprints allowed)
		)
		(placement
			(enabled no)
			(sheetname "")
		)
		(fill
			(thermal_gap 0.5)
			(thermal_bridge_width 0.5)
			(island_removal_mode 0)
		)
		(polygon
			(pts
				(xy 207.154526 -219.107004) (xy 209.186526 -219.107004) (xy 209.186526 -218.878404) (xy 207.154526 -218.878404)
				(xy 207.023208 -218.878404) (xy 206.9973 -218.878404) (xy 206.9973 -219.107004) (xy 207.023208 -219.107004)
			)
		)
	)
	(zone
		(layer "F.Cu")
		(hatch none 0.5)
		(connect_pads
			(clearance 0)
		)
		(min_thickness 0.25)
		(keepout
			(tracks allowed)
			(vias allowed)
			(pads allowed)
			(copperpour allowed)
			(footprints allowed)
		)
		(placement
			(enabled no)
			(sheetname "")
		)
		(fill
			(thermal_gap 0.5)
			(thermal_bridge_width 0.5)
			(island_removal_mode 0)
		)
		(polygon
			(pts
				(xy 161.891726 -310.055006) (xy 161.891726 -309.826406) (xy 163.923726 -309.826406) (xy 163.923726 -310.055006)
			)
		)
	)
	(zone
		(layer "F.Cu")
		(hatch none 0.5)
		(connect_pads
			(clearance 0)
		)
		(min_thickness 0.25)
		(keepout
			(tracks allowed)
			(vias allowed)
			(pads allowed)
			(copperpour allowed)
			(footprints allowed)
		)
		(placement
			(enabled no)
			(sheetname "")
		)
		(fill
			(thermal_gap 0.5)
			(thermal_bridge_width 0.5)
			(island_removal_mode 0)
		)
		(polygon
			(pts
				(xy 304.319178 -284.666436) (xy 304.319178 -284.222698) (xy 306.644294 -284.222698) (xy 306.644294 -284.666436)
			)
		)
	)
	(zone
		(layer "F.Cu")
		(hatch none 0.5)
		(connect_pads
			(clearance 0)
		)
		(min_thickness 0.25)
		(keepout
			(tracks allowed)
			(vias allowed)
			(pads allowed)
			(copperpour allowed)
			(footprints allowed)
		)
		(placement
			(enabled no)
			(sheetname "")
		)
		(fill
			(thermal_gap 0.5)
			(thermal_bridge_width 0.5)
			(island_removal_mode 0)
		)
		(polygon
			(pts
				(xy 385.75234 -218.468448) (xy 386.03936 -218.468448) (xy 386.06984 -218.437968) (xy 386.06984 -217.810588)
				(xy 385.98348 -217.724228) (xy 385.79552 -217.724228) (xy 385.72186 -217.797888) (xy 385.72186 -218.437968)
			)
		)
	)
	(zone
		(layer "F.Cu")
		(hatch none 0.5)
		(connect_pads
			(clearance 0)
		)
		(min_thickness 0.25)
		(keepout
			(tracks allowed)
			(vias allowed)
			(pads allowed)
			(copperpour allowed)
			(footprints allowed)
		)
		(placement
			(enabled no)
			(sheetname "")
		)
		(fill
			(thermal_gap 0.5)
			(thermal_bridge_width 0.5)
			(island_removal_mode 0)
		)
		(polygon
			(pts
				(xy 157.791658 -293.05504) (xy 157.791658 -292.82644) (xy 159.823658 -292.82644) (xy 159.823658 -293.05504)
			)
		)
	)
	(zone
		(layer "F.Cu")
		(hatch none 0.5)
		(connect_pads
			(clearance 0)
		)
		(min_thickness 0.25)
		(keepout
			(tracks allowed)
			(vias allowed)
			(pads allowed)
			(copperpour allowed)
			(footprints allowed)
		)
		(placement
			(enabled no)
			(sheetname "")
		)
		(fill
			(thermal_gap 0.5)
			(thermal_bridge_width 0.5)
			(island_removal_mode 0)
		)
		(polygon
			(pts
				(xy 332.202536 -237.469172) (xy 332.405482 -237.672118) (xy 332.448408 -237.672118) (xy 332.892146 -237.228634)
				(xy 332.892146 -237.10646) (xy 332.759304 -236.973364) (xy 332.655164 -236.973364) (xy 332.202536 -237.425992)
			)
		)
	)
	(zone
		(layer "F.Cu")
		(hatch none 0.5)
		(connect_pads
			(clearance 0)
		)
		(min_thickness 0.25)
		(keepout
			(tracks allowed)
			(vias allowed)
			(pads allowed)
			(copperpour allowed)
			(footprints allowed)
		)
		(placement
			(enabled no)
			(sheetname "")
		)
		(fill
			(thermal_gap 0.5)
			(thermal_bridge_width 0.5)
			(island_removal_mode 0)
		)
		(polygon
			(pts
				(xy 458.538326 -316.004956) (xy 458.538326 -315.776356) (xy 460.570326 -315.776356) (xy 460.570326 -316.004956)
			)
		)
	)
	(zone
		(layer "F.Cu")
		(hatch none 0.5)
		(connect_pads
			(clearance 0)
		)
		(min_thickness 0.25)
		(keepout
			(tracks allowed)
			(vias allowed)
			(pads allowed)
			(copperpour allowed)
			(footprints allowed)
		)
		(placement
			(enabled no)
			(sheetname "")
		)
		(fill
			(thermal_gap 0.5)
			(thermal_bridge_width 0.5)
			(island_removal_mode 0)
		)
		(polygon
			(pts
				(xy 39.51732 -343.002108) (xy 39.51732 -339.89772) (xy 43.58894 -339.89772) (xy 43.58894 -343.002108)
			)
		)
	)
	(zone
		(layer "F.Cu")
		(hatch none 0.5)
		(connect_pads
			(clearance 0)
		)
		(min_thickness 0.25)
		(keepout
			(tracks allowed)
			(vias allowed)
			(pads allowed)
			(copperpour allowed)
			(footprints allowed)
		)
		(placement
			(enabled no)
			(sheetname "")
		)
		(fill
			(thermal_gap 0.5)
			(thermal_bridge_width 0.5)
			(island_removal_mode 0)
		)
		(polygon
			(pts
				(xy 455.094594 -298.77639) (xy 457.126594 -298.77639) (xy 457.126594 -299.00499) (xy 455.094594 -299.00499)
				(xy 454.95845 -299.00499) (xy 454.91146 -299.00499) (xy 454.91146 -298.77639) (xy 454.95845 -298.77639)
			)
		)
	)
	(zone
		(layer "F.Cu")
		(hatch none 0.5)
		(connect_pads
			(clearance 0)
		)
		(min_thickness 0.25)
		(keepout
			(tracks not_allowed)
			(vias allowed)
			(pads allowed)
			(copperpour not_allowed)
			(footprints allowed)
		)
		(placement
			(enabled no)
			(sheetname "")
		)
		(fill
			(thermal_gap 0.5)
			(thermal_bridge_width 0.5)
			(island_removal_mode 0)
		)
		(polygon
			(pts
				(xy 342.893142 -336.26044) (xy 346.82684 -336.26044) (xy 346.82684 -336.212688) (xy 346.68968 -336.075528)
				(xy 345.280996 -336.075528) (xy 345.280996 -333.916528) (xy 347.43771 -333.916528) (xy 347.43771 -333.666846)
				(xy 345.1098 -333.666846) (xy 345.1098 -333.992728) (xy 344.989658 -333.992728) (xy 344.989658 -336.019902)
				(xy 343.135458 -336.019902) (xy 343.135458 -335.778856) (xy 342.893142 -335.778856)
			)
		)
	)
	(zone
		(layer "F.Cu")
		(hatch none 0.5)
		(connect_pads
			(clearance 0)
		)
		(min_thickness 0.25)
		(keepout
			(tracks allowed)
			(vias allowed)
			(pads allowed)
			(copperpour allowed)
			(footprints allowed)
		)
		(placement
			(enabled no)
			(sheetname "")
		)
		(fill
			(thermal_gap 0.5)
			(thermal_bridge_width 0.5)
			(island_removal_mode 0)
		)
		(polygon
			(pts
				(xy 26.20391 -260.866636) (xy 26.20391 -260.422898) (xy 28.529026 -260.422898) (xy 28.529026 -260.866636)
			)
		)
	)
	(zone
		(layer "F.Cu")
		(hatch none 0.5)
		(connect_pads
			(clearance 0)
		)
		(min_thickness 0.25)
		(keepout
			(tracks allowed)
			(vias allowed)
			(pads allowed)
			(copperpour allowed)
			(footprints allowed)
		)
		(placement
			(enabled no)
			(sheetname "")
		)
		(fill
			(thermal_gap 0.5)
			(thermal_bridge_width 0.5)
			(island_removal_mode 0)
		)
		(polygon
			(pts
				(xy 210.261962 -395.37767) (xy 210.261962 -393.637008) (xy 212.177376 -393.637008) (xy 212.177376 -395.37767)
			)
		)
	)
	(zone
		(layer "F.Cu")
		(hatch none 0.5)
		(connect_pads
			(clearance 0)
		)
		(min_thickness 0.25)
		(keepout
			(tracks allowed)
			(vias allowed)
			(pads allowed)
			(copperpour allowed)
			(footprints allowed)
		)
		(placement
			(enabled no)
			(sheetname "")
		)
		(fill
			(thermal_gap 0.5)
			(thermal_bridge_width 0.5)
			(island_removal_mode 0)
		)
		(polygon
			(pts
				(xy 85.62848 -217.681048) (xy 85.9155 -217.681048) (xy 85.94598 -217.650568) (xy 85.94598 -217.023188)
				(xy 85.85962 -216.936828) (xy 85.67166 -216.936828) (xy 85.598 -217.010488) (xy 85.598 -217.650568)
			)
		)
	)
	(zone
		(layer "F.Cu")
		(hatch none 0.5)
		(connect_pads
			(clearance 0)
		)
		(min_thickness 0.25)
		(keepout
			(tracks allowed)
			(vias allowed)
			(pads allowed)
			(copperpour allowed)
			(footprints allowed)
		)
		(placement
			(enabled no)
			(sheetname "")
		)
		(fill
			(thermal_gap 0.5)
			(thermal_bridge_width 0.5)
			(island_removal_mode 0)
		)
		(polygon
			(pts
				(xy 161.891726 -304.72634) (xy 163.923726 -304.72634) (xy 163.923726 -304.95494) (xy 161.891726 -304.95494)
				(xy 161.710624 -304.95494) (xy 161.710624 -304.72634)
			)
		)
	)
	(zone
		(layer "F.Cu")
		(hatch none 0.5)
		(connect_pads
			(clearance 0)
		)
		(min_thickness 0.25)
		(keepout
			(tracks allowed)
			(vias allowed)
			(pads allowed)
			(copperpour allowed)
			(footprints allowed)
		)
		(placement
			(enabled no)
			(sheetname "")
		)
		(fill
			(thermal_gap 0.5)
			(thermal_bridge_width 0.5)
			(island_removal_mode 0)
		)
		(polygon
			(pts
				(xy 26.20391 -224.316544) (xy 26.20391 -223.872806) (xy 28.529026 -223.872806) (xy 28.529026 -224.316544)
			)
		)
	)
	(zone
		(layer "F.Cu")
		(hatch none 0.5)
		(connect_pads
			(clearance 0)
		)
		(min_thickness 0.25)
		(keepout
			(tracks allowed)
			(vias allowed)
			(pads allowed)
			(copperpour allowed)
			(footprints not_allowed)
		)
		(placement
			(enabled no)
			(sheetname "")
		)
		(fill
			(thermal_gap 0.5)
			(thermal_bridge_width 0.5)
			(island_removal_mode 0)
		)
		(polygon
			(pts
				(xy 80.669892 -52.55006) (xy 107.430062 -52.55006) (xy 107.430062 -41.550082) (xy 80.674464 -41.550082)
			)
		)
	)
	(zone
		(layer "F.Cu")
		(hatch none 0.5)
		(connect_pads
			(clearance 0)
		)
		(min_thickness 0.25)
		(keepout
			(tracks allowed)
			(vias allowed)
			(pads allowed)
			(copperpour allowed)
			(footprints not_allowed)
		)
		(placement
			(enabled no)
			(sheetname "")
		)
		(fill
			(thermal_gap 0.5)
			(thermal_bridge_width 0.5)
			(island_removal_mode 0)
		)
		(polygon
			(pts
				(xy 327.620122 -292.770052) (xy 392.12012 -292.770052) (xy 392.12012 -210.769962) (xy 327.620122 -210.769962)
			)
		)
	)
	(zone
		(layer "F.Cu")
		(hatch none 0.5)
		(connect_pads
			(clearance 0)
		)
		(min_thickness 0.25)
		(keepout
			(tracks allowed)
			(vias allowed)
			(pads allowed)
			(copperpour allowed)
			(footprints allowed)
		)
		(placement
			(enabled no)
			(sheetname "")
		)
		(fill
			(thermal_gap 0.5)
			(thermal_bridge_width 0.5)
			(island_removal_mode 0)
		)
		(polygon
			(pts
				(xy 292.67531 -220.9165) (xy 292.67531 -220.472762) (xy 295.000426 -220.472762) (xy 295.000426 -220.9165)
			)
		)
	)
	(zone
		(layer "F.Cu")
		(hatch none 0.5)
		(connect_pads
			(clearance 0)
		)
		(min_thickness 0.25)
		(keepout
			(tracks allowed)
			(vias allowed)
			(pads allowed)
			(copperpour allowed)
			(footprints allowed)
		)
		(placement
			(enabled no)
			(sheetname "")
		)
		(fill
			(thermal_gap 0.5)
			(thermal_bridge_width 0.5)
			(island_removal_mode 0)
		)
		(polygon
			(pts
				(xy 325.3359 -348.160848) (xy 325.3359 -345.519248) (xy 330.5556 -345.519248) (xy 330.5556 -348.160848)
			)
		)
	)
	(zone
		(layer "F.Cu")
		(hatch none 0.5)
		(connect_pads
			(clearance 0)
		)
		(min_thickness 0.25)
		(keepout
			(tracks allowed)
			(vias allowed)
			(pads allowed)
			(copperpour allowed)
			(footprints allowed)
		)
		(placement
			(enabled no)
			(sheetname "")
		)
		(fill
			(thermal_gap 0.5)
			(thermal_bridge_width 0.5)
			(island_removal_mode 0)
		)
		(polygon
			(pts
				(xy 28.52928 -238.76635) (xy 26.204164 -238.76635) (xy 26.065734 -238.76635) (xy 26.065734 -237.580424)
				(xy 28.590494 -237.580424) (xy 28.590494 -238.76635)
			)
		)
	)
	(zone
		(layer "F.Cu")
		(hatch none 0.5)
		(connect_pads
			(clearance 0)
		)
		(min_thickness 0.25)
		(keepout
			(tracks allowed)
			(vias allowed)
			(pads allowed)
			(copperpour allowed)
			(footprints allowed)
		)
		(placement
			(enabled no)
			(sheetname "")
		)
		(fill
			(thermal_gap 0.5)
			(thermal_bridge_width 0.5)
			(island_removal_mode 0)
		)
		(polygon
			(pts
				(xy 44.735242 -296.56659) (xy 44.735242 -296.122852) (xy 47.060358 -296.122852) (xy 47.060358 -296.56659)
			)
		)
	)
	(zone
		(layer "F.Cu")
		(hatch none 0.5)
		(connect_pads
			(clearance 0)
		)
		(min_thickness 0.25)
		(keepout
			(tracks allowed)
			(vias allowed)
			(pads allowed)
			(copperpour allowed)
			(footprints allowed)
		)
		(placement
			(enabled no)
			(sheetname "")
		)
		(fill
			(thermal_gap 0.5)
			(thermal_bridge_width 0.5)
			(island_removal_mode 0)
		)
		(polygon
			(pts
				(xy 44.735242 -286.366458) (xy 44.735242 -285.92272) (xy 47.060358 -285.92272) (xy 47.060358 -286.366458)
			)
		)
	)
	(zone
		(layer "F.Cu")
		(hatch none 0.5)
		(connect_pads
			(clearance 0)
		)
		(min_thickness 0.25)
		(keepout
			(tracks allowed)
			(vias allowed)
			(pads allowed)
			(copperpour allowed)
			(footprints allowed)
		)
		(placement
			(enabled no)
			(sheetname "")
		)
		(fill
			(thermal_gap 0.5)
			(thermal_bridge_width 0.5)
			(island_removal_mode 0)
		)
		(polygon
			(pts
				(xy 137.44448 -284.142688) (xy 137.7315 -284.142688) (xy 137.76198 -284.112208) (xy 137.76198 -283.484828)
				(xy 137.67562 -283.398468) (xy 137.48766 -283.398468) (xy 137.414 -283.472128) (xy 137.414 -284.112208)
			)
		)
	)
	(zone
		(layer "F.Cu")
		(hatch none 0.5)
		(connect_pads
			(clearance 0)
		)
		(min_thickness 0.25)
		(keepout
			(tracks not_allowed)
			(vias allowed)
			(pads allowed)
			(copperpour not_allowed)
			(footprints allowed)
		)
		(placement
			(enabled no)
			(sheetname "")
		)
		(fill
			(thermal_gap 0.5)
			(thermal_bridge_width 0.5)
			(island_removal_mode 0)
		)
		(polygon
			(pts
				(arc
					(start 135.514842 -297.515026)
					(mid 133.41985 -299.610018)
					(end 131.324858 -297.515026)
				)
				(arc
					(start 131.324858 -297.515026)
					(mid 133.41985 -295.420034)
					(end 135.514842 -297.515026)
				)
			)
		)
	)
	(zone
		(layer "F.Cu")
		(hatch none 0.5)
		(connect_pads
			(clearance 0)
		)
		(min_thickness 0.25)
		(keepout
			(tracks allowed)
			(vias allowed)
			(pads allowed)
			(copperpour allowed)
			(footprints allowed)
		)
		(placement
			(enabled no)
			(sheetname "")
		)
		(fill
			(thermal_gap 0.5)
			(thermal_bridge_width 0.5)
			(island_removal_mode 0)
		)
		(polygon
			(pts
				(xy 277.58771 -247.26646) (xy 277.58771 -246.822722) (xy 279.912826 -246.822722) (xy 279.912826 -247.26646)
			)
		)
	)
	(zone
		(layer "F.Cu")
		(hatch none 0.5)
		(connect_pads
			(clearance 0)
		)
		(min_thickness 0.25)
		(keepout
			(tracks allowed)
			(vias allowed)
			(pads allowed)
			(copperpour allowed)
			(footprints allowed)
		)
		(placement
			(enabled no)
			(sheetname "")
		)
		(fill
			(thermal_gap 0.5)
			(thermal_bridge_width 0.5)
			(island_removal_mode 0)
		)
		(polygon
			(pts
				(xy 424.919394 -272.42643) (xy 426.951394 -272.42643) (xy 426.951394 -272.65503) (xy 424.919394 -272.65503)
				(xy 424.78325 -272.65503) (xy 424.73626 -272.65503) (xy 424.73626 -272.42643) (xy 424.78325 -272.42643)
			)
		)
	)
	(zone
		(layer "F.Cu")
		(hatch none 0.5)
		(connect_pads
			(clearance 0)
		)
		(min_thickness 0.25)
		(keepout
			(tracks allowed)
			(vias allowed)
			(pads allowed)
			(copperpour allowed)
			(footprints allowed)
		)
		(placement
			(enabled no)
			(sheetname "")
		)
		(fill
			(thermal_gap 0.5)
			(thermal_bridge_width 0.5)
			(island_removal_mode 0)
		)
		(polygon
			(pts
				(xy 315.776102 -404.802594) (xy 315.776102 -399.959576) (xy 317.660528 -399.959576) (xy 317.660528 -404.802594)
			)
		)
	)
	(zone
		(layer "F.Cu")
		(hatch none 0.5)
		(connect_pads
			(clearance 0)
		)
		(min_thickness 0.25)
		(keepout
			(tracks allowed)
			(vias allowed)
			(pads allowed)
			(copperpour allowed)
			(footprints allowed)
		)
		(placement
			(enabled no)
			(sheetname "")
		)
		(fill
			(thermal_gap 0.5)
			(thermal_bridge_width 0.5)
			(island_removal_mode 0)
		)
		(polygon
			(pts
				(xy 418.252402 -170.83024) (xy 418.252402 -172.57776) (xy 416.316922 -172.57776) (xy 416.316922 -170.83024)
			)
		)
	)
	(zone
		(layer "F.Cu")
		(hatch none 0.5)
		(connect_pads
			(clearance 0)
		)
		(min_thickness 0.25)
		(keepout
			(tracks allowed)
			(vias allowed)
			(pads allowed)
			(copperpour allowed)
			(footprints allowed)
		)
		(placement
			(enabled no)
			(sheetname "")
		)
		(fill
			(thermal_gap 0.5)
			(thermal_bridge_width 0.5)
			(island_removal_mode 0)
		)
		(polygon
			(pts
				(xy 140.074396 -257.549904) (xy 141.986508 -259.461762) (xy 142.171674 -259.646928) (xy 142.244572 -259.646928)
				(xy 144.548352 -261.950708) (xy 144.746472 -261.950708) (xy 145.411952 -261.285228) (xy 145.411952 -261.135368)
				(xy 145.411952 -261.079488) (xy 146.306032 -260.185408) (xy 146.306032 -260.063488) (xy 146.747992 -259.621528)
				(xy 147.154392 -259.621528) (xy 147.479512 -259.296408) (xy 147.860512 -259.296408) (xy 148.940012 -258.216908)
				(xy 148.959062 -258.197858) (xy 148.959062 -258.162298) (xy 148.774912 -257.978148) (xy 145.549112 -257.978148)
				(xy 145.447512 -257.876548) (xy 145.447512 -256.695448) (xy 145.432272 -256.680208) (xy 145.350992 -256.680208)
				(xy 145.324576 -256.653792) (xy 145.323052 -256.652268) (xy 145.323052 -255.974088) (xy 144.708372 -255.974088)
				(xy 144.041622 -255.307338) (xy 144.004792 -255.270508) (xy 144.004792 -255.196848) (xy 144.502632 -254.699008)
				(xy 146.84121 -254.699008) (xy 146.84121 -253.915164) (xy 145.322544 -253.915164) (xy 145.208498 -253.801118)
				(xy 144.62252 -253.21514) (xy 144.019524 -253.21514) (xy 143.511016 -252.706632) (xy 143.511016 -251.743464)
				(xy 143.511016 -251.29617) (xy 140.424916 -251.296424) (xy 140.177012 -251.04852) (xy 136.744202 -251.04852)
				(xy 136.55929 -250.863608) (xy 136.141206 -250.863608) (xy 135.715248 -250.43765) (xy 135.715248 -250.107958)
				(xy 135.562594 -249.955304) (xy 132.64896 -249.955304) (xy 132.544312 -250.059952) (xy 132.544312 -250.242832)
				(xy 132.594604 -250.242832) (xy 132.996178 -250.644406) (xy 133.308344 -250.8631) (xy 134.912608 -251.705618)
				(xy 135.357108 -251.900944) (xy 135.420608 -251.940822) (xy 135.420608 -252.153674) (xy 135.471662 -252.204728)
				(xy 135.98906 -252.521212) (xy 136.534652 -252.654562) (xy 136.565132 -252.685042) (xy 136.565132 -252.854968)
				(xy 136.841484 -253.13132) (xy 136.891268 -253.13132) (xy 138.583416 -253.13132) (xy 140.479272 -253.527814)
				(xy 140.497052 -253.545594) (xy 140.497052 -253.844298) (xy 140.467842 -253.873508) (xy 140.467842 -253.910592)
				(xy 140.52931 -253.97206) (xy 140.648436 -253.97206) (xy 140.944854 -254.268478) (xy 140.944854 -254.533908)
				(xy 140.895578 -254.583184) (xy 140.387578 -254.583184) (xy 140.374116 -254.596646) (xy 140.374116 -255.411732)
				(xy 140.247116 -255.538732) (xy 140.10259 -255.538732) (xy 139.977622 -255.6637) (xy 139.977622 -255.852168)
				(xy 140.074396 -255.948942)
			)
		)
	)
	(zone
		(layer "F.Cu")
		(hatch none 0.5)
		(connect_pads
			(clearance 0)
		)
		(min_thickness 0.25)
		(keepout
			(tracks allowed)
			(vias allowed)
			(pads allowed)
			(copperpour allowed)
			(footprints allowed)
		)
		(placement
			(enabled no)
			(sheetname "")
		)
		(fill
			(thermal_gap 0.5)
			(thermal_bridge_width 0.5)
			(island_removal_mode 0)
		)
		(polygon
			(pts
				(xy 210.598258 -262.454898) (xy 210.598258 -262.226298) (xy 212.630258 -262.226298) (xy 212.630258 -262.454898)
			)
		)
	)
	(zone
		(layer "F.Cu")
		(hatch none 0.5)
		(connect_pads
			(clearance 0)
		)
		(min_thickness 0.25)
		(keepout
			(tracks allowed)
			(vias allowed)
			(pads allowed)
			(copperpour allowed)
			(footprints allowed)
		)
		(placement
			(enabled no)
			(sheetname "")
		)
		(fill
			(thermal_gap 0.5)
			(thermal_bridge_width 0.5)
			(island_removal_mode 0)
		)
		(polygon
			(pts
				(xy 458.538326 -289.654996) (xy 458.538326 -289.426396) (xy 460.570326 -289.426396) (xy 460.570326 -289.654996)
			)
		)
	)
	(zone
		(layer "F.Cu")
		(hatch none 0.5)
		(connect_pads
			(clearance 0)
		)
		(min_thickness 0.25)
		(keepout
			(tracks allowed)
			(vias allowed)
			(pads allowed)
			(copperpour allowed)
			(footprints allowed)
		)
		(placement
			(enabled no)
			(sheetname "")
		)
		(fill
			(thermal_gap 0.5)
			(thermal_bridge_width 0.5)
			(island_removal_mode 0)
		)
		(polygon
			(pts
				(xy 207.154526 -201.876406) (xy 209.186526 -201.876406) (xy 209.186526 -202.105006) (xy 207.154526 -202.105006)
				(xy 207.018382 -202.105006) (xy 206.971392 -202.105006) (xy 206.971392 -201.876406) (xy 207.018382 -201.876406)
			)
		)
	)
	(zone
		(layer "F.Cu")
		(hatch none 0.5)
		(connect_pads
			(clearance 0)
		)
		(min_thickness 0.25)
		(keepout
			(tracks allowed)
			(vias allowed)
			(pads allowed)
			(copperpour allowed)
			(footprints allowed)
		)
		(placement
			(enabled no)
			(sheetname "")
		)
		(fill
			(thermal_gap 0.5)
			(thermal_bridge_width 0.5)
			(island_removal_mode 0)
		)
		(polygon
			(pts
				(xy 424.919394 -238.426244) (xy 426.951394 -238.426244) (xy 426.951394 -238.654844) (xy 424.919394 -238.654844)
				(xy 424.788076 -238.654844) (xy 424.762168 -238.654844) (xy 424.762168 -238.426244) (xy 424.788076 -238.426244)
			)
		)
	)
	(zone
		(layer "F.Cu")
		(hatch none 0.5)
		(connect_pads
			(clearance 0)
		)
		(min_thickness 0.25)
		(keepout
			(tracks allowed)
			(vias allowed)
			(pads allowed)
			(copperpour allowed)
			(footprints allowed)
		)
		(placement
			(enabled no)
			(sheetname "")
		)
		(fill
			(thermal_gap 0.5)
			(thermal_bridge_width 0.5)
			(island_removal_mode 0)
		)
		(polygon
			(pts
				(xy 29.647642 -265.966448) (xy 29.647642 -265.52271) (xy 31.972758 -265.52271) (xy 31.972758 -265.966448)
			)
		)
	)
	(zone
		(layer "F.Cu")
		(hatch none 0.5)
		(connect_pads
			(clearance 0)
		)
		(min_thickness 0.25)
		(keepout
			(tracks allowed)
			(vias allowed)
			(pads allowed)
			(copperpour allowed)
			(footprints allowed)
		)
		(placement
			(enabled no)
			(sheetname "")
		)
		(fill
			(thermal_gap 0.5)
			(thermal_bridge_width 0.5)
			(island_removal_mode 0)
		)
		(polygon
			(pts
				(xy 44.735242 -271.066514) (xy 44.735242 -270.622776) (xy 47.060358 -270.622776) (xy 47.060358 -271.066514)
			)
		)
	)
	(zone
		(layer "F.Cu")
		(hatch none 0.5)
		(connect_pads
			(clearance 0)
		)
		(min_thickness 0.25)
		(keepout
			(tracks allowed)
			(vias allowed)
			(pads allowed)
			(copperpour allowed)
			(footprints allowed)
		)
		(placement
			(enabled no)
			(sheetname "")
		)
		(fill
			(thermal_gap 0.5)
			(thermal_bridge_width 0.5)
			(island_removal_mode 0)
		)
		(polygon
			(pts
				(xy 161.891726 -200.404984) (xy 161.891726 -200.176384) (xy 163.923726 -200.176384) (xy 163.923726 -200.404984)
			)
		)
	)
	(zone
		(layer "F.Cu")
		(hatch none 0.5)
		(connect_pads
			(clearance 0)
		)
		(min_thickness 0.25)
		(keepout
			(tracks allowed)
			(vias allowed)
			(pads allowed)
			(copperpour allowed)
			(footprints allowed)
		)
		(placement
			(enabled no)
			(sheetname "")
		)
		(fill
			(thermal_gap 0.5)
			(thermal_bridge_width 0.5)
			(island_removal_mode 0)
		)
		(polygon
			(pts
				(xy 44.735242 -240.466626) (xy 44.735242 -240.022888) (xy 47.060358 -240.022888) (xy 47.060358 -240.466626)
			)
		)
	)
	(zone
		(layer "F.Cu")
		(hatch none 0.5)
		(connect_pads
			(clearance 0)
		)
		(min_thickness 0.25)
		(keepout
			(tracks allowed)
			(vias allowed)
			(pads allowed)
			(copperpour allowed)
			(footprints allowed)
		)
		(placement
			(enabled no)
			(sheetname "")
		)
		(fill
			(thermal_gap 0.5)
			(thermal_bridge_width 0.5)
			(island_removal_mode 0)
		)
		(polygon
			(pts
				(xy 443.450726 -218.254834) (xy 443.450726 -218.026234) (xy 445.482726 -218.026234) (xy 445.482726 -218.254834)
			)
		)
	)
	(zone
		(layer "F.Cu")
		(hatch none 0.5)
		(connect_pads
			(clearance 0)
		)
		(min_thickness 0.25)
		(keepout
			(tracks allowed)
			(vias allowed)
			(pads allowed)
			(copperpour allowed)
			(footprints allowed)
		)
		(placement
			(enabled no)
			(sheetname "")
		)
		(fill
			(thermal_gap 0.5)
			(thermal_bridge_width 0.5)
			(island_removal_mode 0)
		)
		(polygon
			(pts
				(xy 428.363126 -316.004956) (xy 428.363126 -315.776356) (xy 430.395126 -315.776356) (xy 430.395126 -316.004956)
			)
		)
	)
	(zone
		(layer "F.Cu")
		(hatch none 0.5)
		(connect_pads
			(clearance 0)
		)
		(min_thickness 0.25)
		(keepout
			(tracks allowed)
			(vias allowed)
			(pads allowed)
			(copperpour allowed)
			(footprints allowed)
		)
		(placement
			(enabled no)
			(sheetname "")
		)
		(fill
			(thermal_gap 0.5)
			(thermal_bridge_width 0.5)
			(island_removal_mode 0)
		)
		(polygon
			(pts
				(xy 277.58771 -309.316628) (xy 277.58771 -308.87289) (xy 279.912826 -308.87289) (xy 279.912826 -309.316628)
			)
		)
	)
	(zone
		(layer "F.Cu")
		(hatch none 0.5)
		(connect_pads
			(clearance 0)
		)
		(min_thickness 0.25)
		(keepout
			(tracks allowed)
			(vias allowed)
			(pads allowed)
			(copperpour allowed)
			(footprints allowed)
		)
		(placement
			(enabled no)
			(sheetname "")
		)
		(fill
			(thermal_gap 0.5)
			(thermal_bridge_width 0.5)
			(island_removal_mode 0)
		)
		(polygon
			(pts
				(xy 311.91708 -262.566658) (xy 311.91708 -262.12292) (xy 314.12688 -262.12292) (xy 314.12688 -262.566658)
			)
		)
	)
	(zone
		(layer "F.Cu")
		(hatch none 0.5)
		(connect_pads
			(clearance 0)
		)
		(min_thickness 0.25)
		(keepout
			(tracks allowed)
			(vias allowed)
			(pads allowed)
			(copperpour allowed)
			(footprints allowed)
		)
		(placement
			(enabled no)
			(sheetname "")
		)
		(fill
			(thermal_gap 0.5)
			(thermal_bridge_width 0.5)
			(island_removal_mode 0)
		)
		(polygon
			(pts
				(xy 29.647642 -202.216512) (xy 29.647642 -201.772774) (xy 31.972758 -201.772774) (xy 31.972758 -202.216512)
			)
		)
	)
	(zone
		(layer "F.Cu")
		(hatch none 0.5)
		(connect_pads
			(clearance 0)
		)
		(min_thickness 0.25)
		(keepout
			(tracks allowed)
			(vias allowed)
			(pads allowed)
			(copperpour allowed)
			(footprints allowed)
		)
		(placement
			(enabled no)
			(sheetname "")
		)
		(fill
			(thermal_gap 0.5)
			(thermal_bridge_width 0.5)
			(island_removal_mode 0)
		)
		(polygon
			(pts
				(xy 62.147958 -277.016464) (xy 59.822842 -277.016464) (xy 59.509152 -277.016464) (xy 59.509152 -276.002496)
				(xy 62.408308 -276.002496) (xy 62.408308 -277.016464)
			)
		)
	)
	(zone
		(layer "F.Cu")
		(hatch none 0.5)
		(connect_pads
			(clearance 0)
		)
		(min_thickness 0.25)
		(keepout
			(tracks allowed)
			(vias allowed)
			(pads allowed)
			(copperpour allowed)
			(footprints allowed)
		)
		(placement
			(enabled no)
			(sheetname "")
		)
		(fill
			(thermal_gap 0.5)
			(thermal_bridge_width 0.5)
			(island_removal_mode 0)
		)
		(polygon
			(pts
				(xy 82.564732 -410.948886) (xy 82.564732 -406.105868) (xy 84.449158 -406.105868) (xy 84.449158 -410.948886)
			)
		)
	)
	(zone
		(layer "F.Cu")
		(hatch none 0.5)
		(connect_pads
			(clearance 0)
		)
		(min_thickness 0.25)
		(keepout
			(tracks allowed)
			(vias allowed)
			(pads allowed)
			(copperpour allowed)
			(footprints allowed)
		)
		(placement
			(enabled no)
			(sheetname "")
		)
		(fill
			(thermal_gap 0.5)
			(thermal_bridge_width 0.5)
			(island_removal_mode 0)
		)
		(polygon
			(pts
				(xy 333.20736 -284.963108) (xy 333.49438 -284.963108) (xy 333.52486 -284.932628) (xy 333.52486 -284.305248)
				(xy 333.4385 -284.218888) (xy 333.25054 -284.218888) (xy 333.17688 -284.292548) (xy 333.17688 -284.932628)
			)
		)
	)
	(zone
		(layer "F.Cu")
		(hatch none 0.5)
		(connect_pads
			(clearance 0)
		)
		(min_thickness 0.25)
		(keepout
			(tracks allowed)
			(vias allowed)
			(pads allowed)
			(copperpour allowed)
			(footprints allowed)
		)
		(placement
			(enabled no)
			(sheetname "")
		)
		(fill
			(thermal_gap 0.5)
			(thermal_bridge_width 0.5)
			(island_removal_mode 0)
		)
		(polygon
			(pts
				(xy 63.977012 -233.2228) (xy 66.212212 -233.2228) (xy 66.320162 -233.2228) (xy 66.320162 -234.173776)
				(xy 63.775336 -234.173776) (xy 63.775336 -233.2228)
			)
		)
	)
	(zone
		(layer "F.Cu")
		(hatch none 0.5)
		(connect_pads
			(clearance 0)
		)
		(min_thickness 0.25)
		(keepout
			(tracks allowed)
			(vias allowed)
			(pads allowed)
			(copperpour allowed)
			(footprints allowed)
		)
		(placement
			(enabled no)
			(sheetname "")
		)
		(fill
			(thermal_gap 0.5)
			(thermal_bridge_width 0.5)
			(island_removal_mode 0)
		)
		(polygon
			(pts
				(xy 176.979326 -229.926388) (xy 179.011326 -229.926388) (xy 179.011326 -230.154988) (xy 176.979326 -230.154988)
				(xy 176.843182 -230.154988) (xy 176.796192 -230.154988) (xy 176.796192 -229.926388) (xy 176.843182 -229.926388)
			)
		)
	)
	(zone
		(layer "F.Cu")
		(hatch none 0.5)
		(connect_pads
			(clearance 0)
		)
		(min_thickness 0.25)
		(keepout
			(tracks allowed)
			(vias allowed)
			(pads allowed)
			(copperpour allowed)
			(footprints allowed)
		)
		(placement
			(enabled no)
			(sheetname "")
		)
		(fill
			(thermal_gap 0.5)
			(thermal_bridge_width 0.5)
			(island_removal_mode 0)
		)
		(polygon
			(pts
				(xy 59.822842 -299.116496) (xy 59.822842 -298.672758) (xy 62.147958 -298.672758) (xy 62.147958 -299.116496)
			)
		)
	)
	(zone
		(layer "F.Cu")
		(hatch none 0.5)
		(connect_pads
			(clearance 0)
		)
		(min_thickness 0.25)
		(keepout
			(tracks allowed)
			(vias allowed)
			(pads allowed)
			(copperpour allowed)
			(footprints allowed)
		)
		(placement
			(enabled no)
			(sheetname "")
		)
		(fill
			(thermal_gap 0.5)
			(thermal_bridge_width 0.5)
			(island_removal_mode 0)
		)
		(polygon
			(pts
				(xy 195.510658 -282.005024) (xy 195.510658 -281.776424) (xy 197.542658 -281.776424) (xy 197.542658 -282.005024)
			)
		)
	)
	(zone
		(layer "F.Cu")
		(hatch none 0.5)
		(connect_pads
			(clearance 0)
		)
		(min_thickness 0.25)
		(keepout
			(tracks allowed)
			(vias allowed)
			(pads allowed)
			(copperpour allowed)
			(footprints allowed)
		)
		(placement
			(enabled no)
			(sheetname "")
		)
		(fill
			(thermal_gap 0.5)
			(thermal_bridge_width 0.5)
			(island_removal_mode 0)
		)
		(polygon
			(pts
				(xy 25.78862 -171.239688) (xy 25.78862 -168.986708) (xy 26.77668 -168.986708) (xy 26.77668 -171.239688)
			)
		)
	)
	(zone
		(layer "F.Cu")
		(hatch none 0.5)
		(connect_pads
			(clearance 0)
		)
		(min_thickness 0.25)
		(keepout
			(tracks allowed)
			(vias allowed)
			(pads allowed)
			(copperpour allowed)
			(footprints allowed)
		)
		(placement
			(enabled no)
			(sheetname "")
		)
		(fill
			(thermal_gap 0.5)
			(thermal_bridge_width 0.5)
			(island_removal_mode 0)
		)
		(polygon
			(pts
				(xy 192.066926 -298.77639) (xy 194.098926 -298.77639) (xy 194.098926 -299.00499) (xy 192.066926 -299.00499)
				(xy 191.930782 -299.00499) (xy 191.883792 -299.00499) (xy 191.883792 -298.77639) (xy 191.930782 -298.77639)
			)
		)
	)
	(zone
		(layer "F.Cu")
		(hatch none 0.5)
		(connect_pads
			(clearance 0)
		)
		(min_thickness 0.25)
		(keepout
			(tracks allowed)
			(vias allowed)
			(pads allowed)
			(copperpour allowed)
			(footprints allowed)
		)
		(placement
			(enabled no)
			(sheetname "")
		)
		(fill
			(thermal_gap 0.5)
			(thermal_bridge_width 0.5)
			(island_removal_mode 0)
		)
		(polygon
			(pts
				(xy 142.486888 -410.948886) (xy 142.486888 -406.105868) (xy 144.371314 -406.105868) (xy 144.371314 -410.948886)
			)
		)
	)
	(zone
		(layer "F.Cu")
		(hatch none 0.5)
		(connect_pads
			(clearance 0)
		)
		(min_thickness 0.25)
		(keepout
			(tracks allowed)
			(vias allowed)
			(pads allowed)
			(copperpour allowed)
			(footprints allowed)
		)
		(placement
			(enabled no)
			(sheetname "")
		)
		(fill
			(thermal_gap 0.5)
			(thermal_bridge_width 0.5)
			(island_removal_mode 0)
		)
		(polygon
			(pts
				(xy 63.900812 -251.516642) (xy 63.900812 -251.072904) (xy 66.237612 -251.072904) (xy 66.237612 -251.516642)
			)
		)
	)
	(zone
		(layer "F.Cu")
		(hatch none 0.5)
		(connect_pads
			(clearance 0)
		)
		(min_thickness 0.25)
		(keepout
			(tracks allowed)
			(vias allowed)
			(pads allowed)
			(copperpour allowed)
			(footprints allowed)
		)
		(placement
			(enabled no)
			(sheetname "")
		)
		(fill
			(thermal_gap 0.5)
			(thermal_bridge_width 0.5)
			(island_removal_mode 0)
		)
		(polygon
			(pts
				(xy 262.50011 -245.566438) (xy 262.50011 -245.1227) (xy 264.825226 -245.1227) (xy 264.825226 -245.566438)
			)
		)
	)
	(zone
		(layer "F.Cu")
		(hatch none 0.5)
		(connect_pads
			(clearance 0)
		)
		(min_thickness 0.25)
		(keepout
			(tracks not_allowed)
			(vias allowed)
			(pads allowed)
			(copperpour not_allowed)
			(footprints allowed)
		)
		(placement
			(enabled no)
			(sheetname "")
		)
		(fill
			(thermal_gap 0.5)
			(thermal_bridge_width 0.5)
			(island_removal_mode 0)
		)
		(polygon
			(pts
				(xy 179.66817 -356.098602) (xy 183.59374 -356.098602) (xy 183.59374 -356.07371) (xy 183.43372 -355.91369)
				(xy 182.056024 -355.91369) (xy 182.056024 -353.75469) (xy 184.212738 -353.75469) (xy 184.212738 -353.568508)
				(xy 181.9021 -353.568508) (xy 181.9021 -353.817428) (xy 181.764686 -353.817428) (xy 181.764686 -355.858064)
				(xy 179.910486 -355.858064) (xy 179.910486 -355.617018) (xy 179.66817 -355.617018)
			)
		)
	)
	(zone
		(layer "F.Cu")
		(hatch none 0.5)
		(connect_pads
			(clearance 0)
		)
		(min_thickness 0.25)
		(keepout
			(tracks allowed)
			(vias allowed)
			(pads allowed)
			(copperpour allowed)
			(footprints allowed)
		)
		(placement
			(enabled no)
			(sheetname "")
		)
		(fill
			(thermal_gap 0.5)
			(thermal_bridge_width 0.5)
			(island_removal_mode 0)
		)
		(polygon
			(pts
				(xy 294.89654 -368.287808) (xy 294.89654 -365.252508) (xy 301.30242 -365.252508) (xy 301.30242 -368.287808)
			)
		)
	)
	(zone
		(layer "F.Cu")
		(hatch none 0.5)
		(connect_pads
			(clearance 0)
		)
		(min_thickness 0.25)
		(keepout
			(tracks allowed)
			(vias allowed)
			(pads allowed)
			(copperpour allowed)
			(footprints allowed)
		)
		(placement
			(enabled no)
			(sheetname "")
		)
		(fill
			(thermal_gap 0.5)
			(thermal_bridge_width 0.5)
			(island_removal_mode 0)
		)
		(polygon
			(pts
				(xy 63.92291 -291.466524) (xy 63.92291 -291.022786) (xy 66.248026 -291.022786) (xy 66.248026 -291.466524)
			)
		)
	)
	(zone
		(layer "F.Cu")
		(hatch none 0.5)
		(connect_pads
			(clearance 0)
		)
		(min_thickness 0.25)
		(keepout
			(tracks allowed)
			(vias allowed)
			(pads allowed)
			(copperpour allowed)
			(footprints allowed)
		)
		(placement
			(enabled no)
			(sheetname "")
		)
		(fill
			(thermal_gap 0.5)
			(thermal_bridge_width 0.5)
			(island_removal_mode 0)
		)
		(polygon
			(pts
				(xy 304.319178 -286.366458) (xy 304.319178 -285.92272) (xy 306.644294 -285.92272) (xy 306.644294 -286.366458)
			)
		)
	)
	(zone
		(layer "F.Cu")
		(hatch none 0.5)
		(connect_pads
			(clearance 0)
		)
		(min_thickness 0.25)
		(keepout
			(tracks allowed)
			(vias allowed)
			(pads allowed)
			(copperpour allowed)
			(footprints allowed)
		)
		(placement
			(enabled no)
			(sheetname "")
		)
		(fill
			(thermal_gap 0.5)
			(thermal_bridge_width 0.5)
			(island_removal_mode 0)
		)
		(polygon
			(pts
				(xy 63.977012 -209.866484) (xy 63.977012 -209.422746) (xy 66.212212 -209.422746) (xy 66.212212 -209.866484)
			)
		)
	)
	(zone
		(layer "F.Cu")
		(hatch none 0.5)
		(connect_pads
			(clearance 0)
		)
		(min_thickness 0.25)
		(keepout
			(tracks allowed)
			(vias allowed)
			(pads allowed)
			(copperpour allowed)
			(footprints allowed)
		)
		(placement
			(enabled no)
			(sheetname "")
		)
		(fill
			(thermal_gap 0.5)
			(thermal_bridge_width 0.5)
			(island_removal_mode 0)
		)
		(polygon
			(pts
				(xy 29.647642 -292.316662) (xy 29.647642 -291.872924) (xy 31.972758 -291.872924) (xy 31.972758 -292.316662)
			)
		)
	)
	(zone
		(layer "F.Cu")
		(hatch none 0.5)
		(connect_pads
			(clearance 0)
		)
		(min_thickness 0.25)
		(keepout
			(tracks not_allowed)
			(vias allowed)
			(pads allowed)
			(copperpour not_allowed)
			(footprints allowed)
		)
		(placement
			(enabled no)
			(sheetname "")
		)
		(fill
			(thermal_gap 0.5)
			(thermal_bridge_width 0.5)
			(island_removal_mode 0)
		)
		(polygon
			(pts
				(xy 438.168796 -9.0424) (xy 438.344056 -9.0424) (xy 438.371996 -9.01446) (xy 438.371996 -7.62) (xy 438.349136 -7.59714)
				(xy 438.178956 -7.59714) (xy 438.158636 -7.61746) (xy 438.158636 -9.03224)
			)
		)
	)
	(zone
		(layer "F.Cu")
		(hatch none 0.5)
		(connect_pads
			(clearance 0)
		)
		(min_thickness 0.25)
		(keepout
			(tracks allowed)
			(vias allowed)
			(pads allowed)
			(copperpour allowed)
			(footprints allowed)
		)
		(placement
			(enabled no)
			(sheetname "")
		)
		(fill
			(thermal_gap 0.5)
			(thermal_bridge_width 0.5)
			(island_removal_mode 0)
		)
		(polygon
			(pts
				(xy 428.363126 -265.854942) (xy 428.363126 -265.626342) (xy 430.395126 -265.626342) (xy 430.395126 -265.854942)
			)
		)
	)
	(zone
		(layer "F.Cu")
		(hatch none 0.5)
		(connect_pads
			(clearance 0)
		)
		(min_thickness 0.25)
		(keepout
			(tracks allowed)
			(vias allowed)
			(pads allowed)
			(copperpour allowed)
			(footprints not_allowed)
		)
		(placement
			(enabled no)
			(sheetname "")
		)
		(fill
			(thermal_gap 0.5)
			(thermal_bridge_width 0.5)
			(island_removal_mode 0)
		)
		(polygon
			(pts
				(xy 37.315902 -330.091796) (xy 43.415712 -330.091796) (xy 43.415712 -186.09183) (xy 37.315902 -186.09183)
			)
		)
	)
	(zone
		(layer "F.Cu")
		(hatch none 0.5)
		(connect_pads
			(clearance 0)
		)
		(min_thickness 0.25)
		(keepout
			(tracks allowed)
			(vias allowed)
			(pads allowed)
			(copperpour allowed)
			(footprints allowed)
		)
		(placement
			(enabled no)
			(sheetname "")
		)
		(fill
			(thermal_gap 0.5)
			(thermal_bridge_width 0.5)
			(island_removal_mode 0)
		)
		(polygon
			(pts
				(xy 277.58771 -293.166546) (xy 277.58771 -292.722808) (xy 279.912826 -292.722808) (xy 279.912826 -293.166546)
			)
		)
	)
	(zone
		(layer "F.Cu")
		(hatch none 0.5)
		(connect_pads
			(clearance 0)
		)
		(min_thickness 0.25)
		(keepout
			(tracks allowed)
			(vias allowed)
			(pads allowed)
			(copperpour allowed)
			(footprints not_allowed)
		)
		(placement
			(enabled no)
			(sheetname "")
		)
		(fill
			(thermal_gap 0.5)
			(thermal_bridge_width 0.5)
			(island_removal_mode 0)
		)
		(polygon
			(pts
				(xy 21.049996 -63.324994) (xy 21.049996 -40.675052) (xy 14.750034 -40.675052) (xy 14.750034 -63.324994)
			)
		)
	)
	(zone
		(layer "F.Cu")
		(hatch none 0.5)
		(connect_pads
			(clearance 0)
		)
		(min_thickness 0.25)
		(keepout
			(tracks allowed)
			(vias allowed)
			(pads allowed)
			(copperpour allowed)
			(footprints allowed)
		)
		(placement
			(enabled no)
			(sheetname "")
		)
		(fill
			(thermal_gap 0.5)
			(thermal_bridge_width 0.5)
			(island_removal_mode 0)
		)
		(polygon
			(pts
				(xy 145.550128 -410.948886) (xy 145.550128 -406.105868) (xy 147.434554 -406.105868) (xy 147.434554 -410.948886)
			)
		)
	)
	(zone
		(layer "F.Cu")
		(hatch none 0.5)
		(connect_pads
			(clearance 0)
		)
		(min_thickness 0.25)
		(keepout
			(tracks allowed)
			(vias allowed)
			(pads allowed)
			(copperpour allowed)
			(footprints allowed)
		)
		(placement
			(enabled no)
			(sheetname "")
		)
		(fill
			(thermal_gap 0.5)
			(thermal_bridge_width 0.5)
			(island_removal_mode 0)
		)
		(polygon
			(pts
				(xy 167.367458 -235.2548) (xy 165.335458 -235.2548) (xy 165.157658 -235.2548) (xy 165.157658 -234.714288)
				(xy 167.858694 -234.714288) (xy 167.858694 -235.2548)
			)
		)
	)
	(zone
		(layer "F.Cu")
		(hatch none 0.5)
		(connect_pads
			(clearance 0)
		)
		(min_thickness 0.25)
		(keepout
			(tracks allowed)
			(vias allowed)
			(pads allowed)
			(copperpour allowed)
			(footprints allowed)
		)
		(placement
			(enabled no)
			(sheetname "")
		)
		(fill
			(thermal_gap 0.5)
			(thermal_bridge_width 0.5)
			(island_removal_mode 0)
		)
		(polygon
			(pts
				(xy 277.58771 -305.066446) (xy 277.58771 -304.622708) (xy 279.912826 -304.622708) (xy 279.912826 -305.066446)
			)
		)
	)
	(zone
		(layer "F.Cu")
		(hatch none 0.5)
		(connect_pads
			(clearance 0)
		)
		(min_thickness 0.25)
		(keepout
			(tracks allowed)
			(vias allowed)
			(pads allowed)
			(copperpour allowed)
			(footprints allowed)
		)
		(placement
			(enabled no)
			(sheetname "")
		)
		(fill
			(thermal_gap 0.5)
			(thermal_bridge_width 0.5)
			(island_removal_mode 0)
		)
		(polygon
			(pts
				(xy 14.560042 -308.46649) (xy 14.560042 -308.022752) (xy 16.885158 -308.022752) (xy 16.885158 -308.46649)
			)
		)
	)
	(zone
		(layer "F.Cu")
		(hatch none 0.5)
		(connect_pads
			(clearance 0)
		)
		(min_thickness 0.25)
		(keepout
			(tracks allowed)
			(vias allowed)
			(pads allowed)
			(copperpour allowed)
			(footprints allowed)
		)
		(placement
			(enabled no)
			(sheetname "")
		)
		(fill
			(thermal_gap 0.5)
			(thermal_bridge_width 0.5)
			(island_removal_mode 0)
		)
		(polygon
			(pts
				(xy 56.37911 -239.17275) (xy 58.704226 -239.17275) (xy 58.79084 -239.17275) (xy 58.79084 -240.120932)
				(xy 56.19369 -240.120932) (xy 56.19369 -239.17275)
			)
		)
	)
	(zone
		(layer "F.Cu")
		(hatch none 0.5)
		(connect_pads
			(clearance 0)
		)
		(min_thickness 0.25)
		(keepout
			(tracks allowed)
			(vias allowed)
			(pads allowed)
			(copperpour allowed)
			(footprints allowed)
		)
		(placement
			(enabled no)
			(sheetname "")
		)
		(fill
			(thermal_gap 0.5)
			(thermal_bridge_width 0.5)
			(island_removal_mode 0)
		)
		(polygon
			(pts
				(xy 385.84632 -283.337508) (xy 386.13334 -283.337508) (xy 386.16382 -283.307028) (xy 386.16382 -282.679648)
				(xy 386.07746 -282.593288) (xy 385.8895 -282.593288) (xy 385.81584 -282.666948) (xy 385.81584 -283.307028)
			)
		)
	)
	(zone
		(layer "F.Cu")
		(hatch none 0.5)
		(connect_pads
			(clearance 0)
		)
		(min_thickness 0.25)
		(keepout
			(tracks not_allowed)
			(vias allowed)
			(pads allowed)
			(copperpour not_allowed)
			(footprints allowed)
		)
		(placement
			(enabled no)
			(sheetname "")
		)
		(fill
			(thermal_gap 0.5)
			(thermal_bridge_width 0.5)
			(island_removal_mode 0)
		)
		(polygon
			(pts
				(xy 127.595376 -337.464908) (xy 127.837692 -337.464908) (xy 127.837692 -337.372706) (xy 128.62814 -337.372706)
				(xy 128.62814 -337.055968) (xy 128.6891 -337.055968) (xy 128.6891 -336.377026) (xy 127.1397 -336.377026)
				(xy 127.1397 -336.833718) (xy 127.835406 -336.833718) (xy 127.835406 -336.67319) (xy 128.394206 -336.67319)
				(xy 128.394206 -337.07959) (xy 127.835406 -337.07959) (xy 127.835406 -336.859118) (xy 127.1397 -336.859118)
				(xy 127.1397 -336.986118) (xy 127.595376 -336.986118)
			)
		)
	)
	(zone
		(layer "F.Cu")
		(hatch none 0.5)
		(connect_pads
			(clearance 0)
		)
		(min_thickness 0.25)
		(keepout
			(tracks allowed)
			(vias allowed)
			(pads allowed)
			(copperpour allowed)
			(footprints allowed)
		)
		(placement
			(enabled no)
			(sheetname "")
		)
		(fill
			(thermal_gap 0.5)
			(thermal_bridge_width 0.5)
			(island_removal_mode 0)
		)
		(polygon
			(pts
				(xy 311.84088 -197.966584) (xy 311.84088 -197.522846) (xy 314.17768 -197.522846) (xy 314.17768 -197.966584)
			)
		)
	)
	(zone
		(layer "F.Cu")
		(hatch none 0.5)
		(connect_pads
			(clearance 0)
		)
		(min_thickness 0.25)
		(keepout
			(tracks allowed)
			(vias allowed)
			(pads allowed)
			(copperpour allowed)
			(footprints allowed)
		)
		(placement
			(enabled no)
			(sheetname "")
		)
		(fill
			(thermal_gap 0.5)
			(thermal_bridge_width 0.5)
			(island_removal_mode 0)
		)
		(polygon
			(pts
				(xy 307.746654 -315.288422) (xy 307.746654 -314.844684) (xy 310.07177 -314.844684) (xy 310.07177 -315.288422)
			)
		)
	)
	(zone
		(layer "F.Cu")
		(hatch none 0.5)
		(connect_pads
			(clearance 0)
		)
		(min_thickness 0.25)
		(keepout
			(tracks allowed)
			(vias allowed)
			(pads allowed)
			(copperpour allowed)
			(footprints allowed)
		)
		(placement
			(enabled no)
			(sheetname "")
		)
		(fill
			(thermal_gap 0.5)
			(thermal_bridge_width 0.5)
			(island_removal_mode 0)
		)
		(polygon
			(pts
				(xy 18.509488 -319.243456) (xy 18.509488 -316.881256) (xy 21.125688 -316.881256) (xy 21.125688 -319.243456)
			)
		)
	)
	(zone
		(layer "F.Cu")
		(hatch none 0.5)
		(connect_pads
			(clearance 0)
		)
		(min_thickness 0.25)
		(keepout
			(tracks allowed)
			(vias allowed)
			(pads allowed)
			(copperpour allowed)
			(footprints allowed)
		)
		(placement
			(enabled no)
			(sheetname "")
		)
		(fill
			(thermal_gap 0.5)
			(thermal_bridge_width 0.5)
			(island_removal_mode 0)
		)
		(polygon
			(pts
				(xy 31.4706 -174.628048) (xy 31.4706 -173.337728) (xy 39.99484 -173.337728) (xy 39.99484 -174.628048)
			)
		)
	)
	(zone
		(layer "F.Cu")
		(hatch none 0.5)
		(connect_pads
			(clearance 0)
		)
		(min_thickness 0.25)
		(keepout
			(tracks allowed)
			(vias allowed)
			(pads allowed)
			(copperpour allowed)
			(footprints allowed)
		)
		(placement
			(enabled no)
			(sheetname "")
		)
		(fill
			(thermal_gap 0.5)
			(thermal_bridge_width 0.5)
			(island_removal_mode 0)
		)
		(polygon
			(pts
				(xy 136.017 -286.593788) (xy 136.30402 -286.593788) (xy 136.3345 -286.563308) (xy 136.3345 -285.935928)
				(xy 136.24814 -285.849568) (xy 136.06018 -285.849568) (xy 135.98652 -285.923228) (xy 135.98652 -286.563308)
			)
		)
	)
	(zone
		(layer "F.Cu")
		(hatch none 0.5)
		(connect_pads
			(clearance 0)
		)
		(min_thickness 0.25)
		(keepout
			(tracks allowed)
			(vias allowed)
			(pads allowed)
			(copperpour allowed)
			(footprints allowed)
		)
		(placement
			(enabled no)
			(sheetname "")
		)
		(fill
			(thermal_gap 0.5)
			(thermal_bridge_width 0.5)
			(island_removal_mode 0)
		)
		(polygon
			(pts
				(xy 14.560042 -214.96655) (xy 14.560042 -214.522812) (xy 16.885158 -214.522812) (xy 16.885158 -214.96655)
			)
		)
	)
	(zone
		(layer "F.Cu")
		(hatch none 0.5)
		(connect_pads
			(clearance 0)
		)
		(min_thickness 0.25)
		(keepout
			(tracks allowed)
			(vias allowed)
			(pads allowed)
			(copperpour allowed)
			(footprints allowed)
		)
		(placement
			(enabled no)
			(sheetname "")
		)
		(fill
			(thermal_gap 0.5)
			(thermal_bridge_width 0.5)
			(island_removal_mode 0)
		)
		(polygon
			(pts
				(xy 31.788862 -18.570702) (xy 31.788862 -15.436088) (xy 33.567624 -15.436088) (xy 33.567624 -18.570702)
			)
		)
	)
	(zone
		(layer "F.Cu")
		(hatch none 0.5)
		(connect_pads
			(clearance 0)
		)
		(min_thickness 0.25)
		(keepout
			(tracks allowed)
			(vias allowed)
			(pads allowed)
			(copperpour allowed)
			(footprints allowed)
		)
		(placement
			(enabled no)
			(sheetname "")
		)
		(fill
			(thermal_gap 0.5)
			(thermal_bridge_width 0.5)
			(island_removal_mode 0)
		)
		(polygon
			(pts
				(xy 161.891726 -239.276382) (xy 163.923726 -239.276382) (xy 164.11702 -239.276382) (xy 164.11702 -239.504982)
				(xy 164.11702 -240.092992) (xy 161.72053 -240.092992) (xy 161.72053 -239.544098) (xy 161.72053 -239.276382)
			)
		)
	)
	(zone
		(layer "F.Cu")
		(hatch none 0.5)
		(connect_pads
			(clearance 0)
		)
		(min_thickness 0.25)
		(keepout
			(tracks allowed)
			(vias allowed)
			(pads allowed)
			(copperpour allowed)
			(footprints allowed)
		)
		(placement
			(enabled no)
			(sheetname "")
		)
		(fill
			(thermal_gap 0.5)
			(thermal_bridge_width 0.5)
			(island_removal_mode 0)
		)
		(polygon
			(pts
				(xy 195.510658 -283.704792) (xy 195.510658 -283.476192) (xy 197.542658 -283.476192) (xy 197.542658 -283.704792)
			)
		)
	)
	(zone
		(layer "F.Cu")
		(hatch none 0.5)
		(connect_pads
			(clearance 0)
		)
		(min_thickness 0.25)
		(keepout
			(tracks not_allowed)
			(vias allowed)
			(pads allowed)
			(copperpour not_allowed)
			(footprints allowed)
		)
		(placement
			(enabled no)
			(sheetname "")
		)
		(fill
			(thermal_gap 0.5)
			(thermal_bridge_width 0.5)
			(island_removal_mode 0)
		)
		(polygon
			(pts
				(arc
					(start 201.895456 -51.999896)
					(mid 204.645514 -49.249838)
					(end 207.395318 -51.999896)
				)
				(arc
					(start 207.395318 -51.999896)
					(mid 204.645514 -54.7497)
					(end 201.895456 -51.999896)
				)
			)
		)
	)
	(zone
		(layer "F.Cu")
		(hatch none 0.5)
		(connect_pads
			(clearance 0)
		)
		(min_thickness 0.25)
		(keepout
			(tracks allowed)
			(vias allowed)
			(pads allowed)
			(copperpour allowed)
			(footprints allowed)
		)
		(placement
			(enabled no)
			(sheetname "")
		)
		(fill
			(thermal_gap 0.5)
			(thermal_bridge_width 0.5)
			(island_removal_mode 0)
		)
		(polygon
			(pts
				(xy 248.7422 -96.286828) (xy 248.7422 -95.230188) (xy 251.19584 -95.230188) (xy 251.19584 -96.286828)
			)
		)
	)
	(zone
		(layer "F.Cu")
		(hatch none 0.5)
		(connect_pads
			(clearance 0)
		)
		(min_thickness 0.25)
		(keepout
			(tracks allowed)
			(vias allowed)
			(pads allowed)
			(copperpour allowed)
			(footprints allowed)
		)
		(placement
			(enabled no)
			(sheetname "")
		)
		(fill
			(thermal_gap 0.5)
			(thermal_bridge_width 0.5)
			(island_removal_mode 0)
		)
		(polygon
			(pts
				(xy 255.11252 -52.910486) (xy 256.17678 -52.910486) (xy 256.55016 -52.537106) (xy 256.55016 -52.234846)
				(xy 255.91516 -51.599846) (xy 254.89408 -51.599846) (xy 254.56896 -51.924966) (xy 254.56896 -52.366926)
			)
		)
	)
	(zone
		(layer "F.Cu")
		(hatch none 0.5)
		(connect_pads
			(clearance 0)
		)
		(min_thickness 0.25)
		(keepout
			(tracks allowed)
			(vias allowed)
			(pads allowed)
			(copperpour allowed)
			(footprints allowed)
		)
		(placement
			(enabled no)
			(sheetname "")
		)
		(fill
			(thermal_gap 0.5)
			(thermal_bridge_width 0.5)
			(island_removal_mode 0)
		)
		(polygon
			(pts
				(xy 314.082684 -271.910556) (xy 311.796684 -271.910556) (xy 311.520586 -271.910556) (xy 311.520586 -270.944594)
				(xy 314.452 -270.944594) (xy 314.452 -271.910556)
			)
		)
	)
	(zone
		(layer "F.Cu")
		(hatch none 0.5)
		(connect_pads
			(clearance 0)
		)
		(min_thickness 0.25)
		(keepout
			(tracks allowed)
			(vias allowed)
			(pads allowed)
			(copperpour allowed)
			(footprints allowed)
		)
		(placement
			(enabled no)
			(sheetname "")
		)
		(fill
			(thermal_gap 0.5)
			(thermal_bridge_width 0.5)
			(island_removal_mode 0)
		)
		(polygon
			(pts
				(xy 91.47556 -336.996786) (xy 87.93988 -336.996786) (xy 87.93988 -334.913986) (xy 91.47556 -334.913986)
			)
		)
	)
	(zone
		(layer "F.Cu")
		(hatch none 0.5)
		(connect_pads
			(clearance 0)
		)
		(min_thickness 0.25)
		(keepout
			(tracks allowed)
			(vias allowed)
			(pads allowed)
			(copperpour allowed)
			(footprints allowed)
		)
		(placement
			(enabled no)
			(sheetname "")
		)
		(fill
			(thermal_gap 0.5)
			(thermal_bridge_width 0.5)
			(island_removal_mode 0)
		)
		(polygon
			(pts
				(xy 207.154526 -304.72634) (xy 209.186526 -304.72634) (xy 209.186526 -304.95494) (xy 207.154526 -304.95494)
				(xy 207.018382 -304.95494) (xy 206.971392 -304.95494) (xy 206.971392 -304.72634) (xy 207.018382 -304.72634)
			)
		)
	)
	(zone
		(layer "F.Cu")
		(hatch none 0.5)
		(connect_pads
			(clearance 0)
		)
		(min_thickness 0.25)
		(keepout
			(tracks allowed)
			(vias allowed)
			(pads allowed)
			(copperpour allowed)
			(footprints allowed)
		)
		(placement
			(enabled no)
			(sheetname "")
		)
		(fill
			(thermal_gap 0.5)
			(thermal_bridge_width 0.5)
			(island_removal_mode 0)
		)
		(polygon
			(pts
				(xy 428.363126 -306.654962) (xy 428.363126 -306.426362) (xy 430.395126 -306.426362) (xy 430.395126 -306.654962)
			)
		)
	)
	(zone
		(layer "F.Cu")
		(hatch none 0.5)
		(connect_pads
			(clearance 0)
		)
		(min_thickness 0.25)
		(keepout
			(tracks allowed)
			(vias allowed)
			(pads allowed)
			(copperpour allowed)
			(footprints allowed)
		)
		(placement
			(enabled no)
			(sheetname "")
		)
		(fill
			(thermal_gap 0.5)
			(thermal_bridge_width 0.5)
			(island_removal_mode 0)
		)
		(polygon
			(pts
				(xy 207.154526 -308.126384) (xy 209.186526 -308.126384) (xy 209.186526 -308.354984) (xy 207.154526 -308.354984)
				(xy 207.018382 -308.354984) (xy 206.971392 -308.354984) (xy 206.971392 -308.126384) (xy 207.018382 -308.126384)
			)
		)
	)
	(zone
		(layer "F.Cu")
		(hatch none 0.5)
		(connect_pads
			(clearance 0)
		)
		(min_thickness 0.25)
		(keepout
			(tracks allowed)
			(vias allowed)
			(pads allowed)
			(copperpour allowed)
			(footprints allowed)
		)
		(placement
			(enabled no)
			(sheetname "")
		)
		(fill
			(thermal_gap 0.5)
			(thermal_bridge_width 0.5)
			(island_removal_mode 0)
		)
		(polygon
			(pts
				(xy 404.661624 -404.802594) (xy 404.661624 -399.959576) (xy 406.54605 -399.959576) (xy 406.54605 -404.802594)
			)
		)
	)
	(zone
		(layer "F.Cu")
		(hatch none 0.5)
		(connect_pads
			(clearance 0)
		)
		(min_thickness 0.25)
		(keepout
			(tracks allowed)
			(vias allowed)
			(pads allowed)
			(copperpour allowed)
			(footprints allowed)
		)
		(placement
			(enabled no)
			(sheetname "")
		)
		(fill
			(thermal_gap 0.5)
			(thermal_bridge_width 0.5)
			(island_removal_mode 0)
		)
		(polygon
			(pts
				(xy 136.36244 -216.047828) (xy 136.64946 -216.047828) (xy 136.67994 -216.017348) (xy 136.67994 -215.389968)
				(xy 136.59358 -215.303608) (xy 136.40562 -215.303608) (xy 136.33196 -215.377268) (xy 136.33196 -216.017348)
			)
		)
	)
	(zone
		(layer "F.Cu")
		(hatch none 0.5)
		(connect_pads
			(clearance 0)
		)
		(min_thickness 0.25)
		(keepout
			(tracks allowed)
			(vias allowed)
			(pads allowed)
			(copperpour allowed)
			(footprints allowed)
		)
		(placement
			(enabled no)
			(sheetname "")
		)
		(fill
			(thermal_gap 0.5)
			(thermal_bridge_width 0.5)
			(island_removal_mode 0)
		)
		(polygon
			(pts
				(xy 350.817942 -410.948886) (xy 350.817942 -406.105868) (xy 352.702368 -406.105868) (xy 352.702368 -410.948886)
			)
		)
	)
	(zone
		(layer "F.Cu")
		(hatch none 0.5)
		(connect_pads
			(clearance 0)
		)
		(min_thickness 0.25)
		(keepout
			(tracks allowed)
			(vias allowed)
			(pads allowed)
			(copperpour allowed)
			(footprints allowed)
		)
		(placement
			(enabled no)
			(sheetname "")
		)
		(fill
			(thermal_gap 0.5)
			(thermal_bridge_width 0.5)
			(island_removal_mode 0)
		)
		(polygon
			(pts
				(xy 409.831794 -252.25502) (xy 409.831794 -252.02642) (xy 411.863794 -252.02642) (xy 411.863794 -252.25502)
				(xy 411.863794 -252.847602) (xy 409.831794 -252.847602)
			)
		)
	)
	(zone
		(layer "F.Cu")
		(hatch none 0.5)
		(connect_pads
			(clearance 0)
		)
		(min_thickness 0.25)
		(keepout
			(tracks allowed)
			(vias allowed)
			(pads allowed)
			(copperpour allowed)
			(footprints allowed)
		)
		(placement
			(enabled no)
			(sheetname "")
		)
		(fill
			(thermal_gap 0.5)
			(thermal_bridge_width 0.5)
			(island_removal_mode 0)
		)
		(polygon
			(pts
				(xy 48.869092 -410.948886) (xy 48.869092 -406.105868) (xy 50.753518 -406.105868) (xy 50.753518 -410.948886)
			)
		)
	)
	(zone
		(layer "F.Cu")
		(hatch none 0.5)
		(connect_pads
			(clearance 0)
		)
		(min_thickness 0.25)
		(keepout
			(tracks allowed)
			(vias allowed)
			(pads allowed)
			(copperpour allowed)
			(footprints allowed)
		)
		(placement
			(enabled no)
			(sheetname "")
		)
		(fill
			(thermal_gap 0.5)
			(thermal_bridge_width 0.5)
			(island_removal_mode 0)
		)
		(polygon
			(pts
				(xy 351.152206 -365.308134) (xy 359.752646 -365.308134) (xy 362.091224 -365.308134) (xy 363.424724 -365.308134)
				(xy 364.987586 -363.745272) (xy 364.987586 -353.326192) (xy 362.562648 -350.901254) (xy 360.217466 -350.901254)
				(xy 347.555566 -350.901254) (xy 347.078046 -351.378774) (xy 347.078046 -359.222294) (xy 347.934026 -360.078274)
				(xy 349.993966 -360.078274) (xy 350.052386 -360.136694) (xy 350.052386 -364.208314)
			)
		)
	)
	(zone
		(layer "F.Cu")
		(hatch none 0.5)
		(connect_pads
			(clearance 0)
		)
		(min_thickness 0.25)
		(keepout
			(tracks allowed)
			(vias allowed)
			(pads allowed)
			(copperpour allowed)
			(footprints allowed)
		)
		(placement
			(enabled no)
			(sheetname "")
		)
		(fill
			(thermal_gap 0.5)
			(thermal_bridge_width 0.5)
			(island_removal_mode 0)
		)
		(polygon
			(pts
				(xy 44.735242 -244.716554) (xy 44.735242 -244.272816) (xy 47.060358 -244.272816) (xy 47.060358 -244.716554)
			)
		)
	)
	(zone
		(layer "F.Cu")
		(hatch none 0.5)
		(connect_pads
			(clearance 0)
		)
		(min_thickness 0.25)
		(keepout
			(tracks allowed)
			(vias allowed)
			(pads allowed)
			(copperpour allowed)
			(footprints allowed)
		)
		(placement
			(enabled no)
			(sheetname "")
		)
		(fill
			(thermal_gap 0.5)
			(thermal_bridge_width 0.5)
			(island_removal_mode 0)
		)
		(polygon
			(pts
				(xy 407.774902 -274.35683) (xy 405.742902 -274.35683) (xy 405.742902 -274.354544) (xy 405.609044 -274.354544)
				(xy 405.609044 -273.564604) (xy 407.899362 -273.564604) (xy 407.899362 -274.35683)
			)
		)
	)
	(zone
		(layer "F.Cu")
		(hatch none 0.5)
		(connect_pads
			(clearance 0)
		)
		(min_thickness 0.25)
		(keepout
			(tracks allowed)
			(vias allowed)
			(pads allowed)
			(copperpour allowed)
			(footprints allowed)
		)
		(placement
			(enabled no)
			(sheetname "")
		)
		(fill
			(thermal_gap 0.5)
			(thermal_bridge_width 0.5)
			(island_removal_mode 0)
		)
		(polygon
			(pts
				(xy 409.831794 -293.904924) (xy 409.831794 -293.676324) (xy 411.863794 -293.676324) (xy 411.863794 -293.904924)
			)
		)
	)
	(zone
		(layer "F.Cu")
		(hatch none 0.5)
		(connect_pads
			(clearance 0)
		)
		(min_thickness 0.25)
		(keepout
			(tracks allowed)
			(vias allowed)
			(pads allowed)
			(copperpour allowed)
			(footprints allowed)
		)
		(placement
			(enabled no)
			(sheetname "")
		)
		(fill
			(thermal_gap 0.5)
			(thermal_bridge_width 0.5)
			(island_removal_mode 0)
		)
		(polygon
			(pts
				(xy 156.11602 -41.097708) (xy 156.11602 -39.736268) (xy 158.81604 -39.736268) (xy 158.81604 -41.097708)
			)
		)
	)
	(zone
		(layer "F.Cu")
		(hatch none 0.5)
		(connect_pads
			(clearance 0)
		)
		(min_thickness 0.25)
		(keepout
			(tracks allowed)
			(vias allowed)
			(pads allowed)
			(copperpour allowed)
			(footprints allowed)
		)
		(placement
			(enabled no)
			(sheetname "")
		)
		(fill
			(thermal_gap 0.5)
			(thermal_bridge_width 0.5)
			(island_removal_mode 0)
		)
		(polygon
			(pts
				(xy 176.979326 -223.976438) (xy 179.011326 -223.976438) (xy 179.011326 -224.205038) (xy 176.979326 -224.205038)
				(xy 176.843182 -224.205038) (xy 176.796192 -224.205038) (xy 176.796192 -223.976438) (xy 176.843182 -223.976438)
			)
		)
	)
	(zone
		(layer "F.Cu")
		(hatch none 0.5)
		(connect_pads
			(clearance 0)
		)
		(min_thickness 0.25)
		(keepout
			(tracks allowed)
			(vias allowed)
			(pads allowed)
			(copperpour allowed)
			(footprints allowed)
		)
		(placement
			(enabled no)
			(sheetname "")
		)
		(fill
			(thermal_gap 0.5)
			(thermal_bridge_width 0.5)
			(island_removal_mode 0)
		)
		(polygon
			(pts
				(xy 292.67531 -215.816434) (xy 292.67531 -215.372696) (xy 295.000426 -215.372696) (xy 295.000426 -215.816434)
			)
		)
	)
	(zone
		(layer "F.Cu")
		(hatch none 0.5)
		(connect_pads
			(clearance 0)
		)
		(min_thickness 0.25)
		(keepout
			(tracks allowed)
			(vias allowed)
			(pads allowed)
			(copperpour allowed)
			(footprints allowed)
		)
		(placement
			(enabled no)
			(sheetname "")
		)
		(fill
			(thermal_gap 0.5)
			(thermal_bridge_width 0.5)
			(island_removal_mode 0)
		)
		(polygon
			(pts
				(xy 11.11631 -237.916466) (xy 11.11631 -237.472728) (xy 13.441426 -237.472728) (xy 13.441426 -237.916466)
			)
		)
	)
	(zone
		(layer "F.Cu")
		(hatch none 0.5)
		(connect_pads
			(clearance 0)
		)
		(min_thickness 0.25)
		(keepout
			(tracks allowed)
			(vias allowed)
			(pads allowed)
			(copperpour allowed)
			(footprints not_allowed)
		)
		(placement
			(enabled no)
			(sheetname "")
		)
		(fill
			(thermal_gap 0.5)
			(thermal_bridge_width 0.5)
			(island_removal_mode 0)
		)
		(polygon
			(pts
				(xy 156.813504 -185.091832) (xy 156.813504 -331.091794) (xy 217.71991 -331.091794) (xy 217.71991 -185.091832)
			)
		)
	)
	(zone
		(layer "F.Cu")
		(hatch none 0.5)
		(connect_pads
			(clearance 0)
		)
		(min_thickness 0.25)
		(keepout
			(tracks allowed)
			(vias allowed)
			(pads allowed)
			(copperpour allowed)
			(footprints allowed)
		)
		(placement
			(enabled no)
			(sheetname "")
		)
		(fill
			(thermal_gap 0.5)
			(thermal_bridge_width 0.5)
			(island_removal_mode 0)
		)
		(polygon
			(pts
				(xy 413.275526 -300.705012) (xy 413.275526 -300.476412) (xy 415.307526 -300.476412) (xy 415.307526 -300.705012)
			)
		)
	)
	(zone
		(layer "F.Cu")
		(hatch none 0.5)
		(connect_pads
			(clearance 0)
		)
		(min_thickness 0.25)
		(keepout
			(tracks allowed)
			(vias allowed)
			(pads allowed)
			(copperpour allowed)
			(footprints allowed)
		)
		(placement
			(enabled no)
			(sheetname "")
		)
		(fill
			(thermal_gap 0.5)
			(thermal_bridge_width 0.5)
			(island_removal_mode 0)
		)
		(polygon
			(pts
				(xy 409.831794 -214.85479) (xy 409.831794 -214.62619) (xy 411.863794 -214.62619) (xy 411.863794 -214.85479)
			)
		)
	)
	(zone
		(layer "F.Cu")
		(hatch none 0.5)
		(connect_pads
			(clearance 0)
		)
		(min_thickness 0.25)
		(keepout
			(tracks allowed)
			(vias allowed)
			(pads allowed)
			(copperpour allowed)
			(footprints not_allowed)
		)
		(placement
			(enabled no)
			(sheetname "")
		)
		(fill
			(thermal_gap 0.5)
			(thermal_bridge_width 0.5)
			(island_removal_mode 0)
		)
		(polygon
			(pts
				(xy 183.45404 -161.280602) (xy 204.453998 -161.282888) (xy 204.456284 -139.282678) (xy 183.456326 -139.280646)
			)
		)
	)
	(zone
		(layer "F.Cu")
		(hatch none 0.5)
		(connect_pads
			(clearance 0)
		)
		(min_thickness 0.25)
		(keepout
			(tracks allowed)
			(vias allowed)
			(pads allowed)
			(copperpour allowed)
			(footprints allowed)
		)
		(placement
			(enabled no)
			(sheetname "")
		)
		(fill
			(thermal_gap 0.5)
			(thermal_bridge_width 0.5)
			(island_removal_mode 0)
		)
		(polygon
			(pts
				(xy 56.37911 -222.616522) (xy 56.37911 -222.172784) (xy 58.704226 -222.172784) (xy 58.704226 -222.616522)
			)
		)
	)
	(zone
		(layer "F.Cu")
		(hatch none 0.5)
		(connect_pads
			(clearance 0)
		)
		(min_thickness 0.25)
		(keepout
			(tracks not_allowed)
			(vias allowed)
			(pads allowed)
			(copperpour not_allowed)
			(footprints allowed)
		)
		(placement
			(enabled no)
			(sheetname "")
		)
		(fill
			(thermal_gap 0.5)
			(thermal_bridge_width 0.5)
			(island_removal_mode 0)
		)
		(polygon
			(pts
				(xy 169.979848 -355.161088) (xy 170.222164 -355.161088) (xy 170.222164 -354.330508) (xy 169.979848 -354.330508)
			)
		)
	)
	(zone
		(layer "F.Cu")
		(hatch none 0.5)
		(connect_pads
			(clearance 0)
		)
		(min_thickness 0.25)
		(keepout
			(tracks allowed)
			(vias allowed)
			(pads allowed)
			(copperpour allowed)
			(footprints allowed)
		)
		(placement
			(enabled no)
			(sheetname "")
		)
		(fill
			(thermal_gap 0.5)
			(thermal_bridge_width 0.5)
			(island_removal_mode 0)
		)
		(polygon
			(pts
				(xy 424.919394 -205.27645) (xy 426.951394 -205.27645) (xy 426.951394 -205.50505) (xy 424.919394 -205.50505)
				(xy 424.78325 -205.50505) (xy 424.73626 -205.50505) (xy 424.73626 -205.27645) (xy 424.78325 -205.27645)
			)
		)
	)
	(zone
		(layer "F.Cu")
		(hatch none 0.5)
		(connect_pads
			(clearance 0)
		)
		(min_thickness 0.25)
		(keepout
			(tracks not_allowed)
			(vias allowed)
			(pads allowed)
			(copperpour not_allowed)
			(footprints allowed)
		)
		(placement
			(enabled no)
			(sheetname "")
		)
		(fill
			(thermal_gap 0.5)
			(thermal_bridge_width 0.5)
			(island_removal_mode 0)
		)
		(polygon
			(pts
				(xy 359.456482 -335.338928) (xy 359.456482 -334.358488) (xy 359.214166 -334.358488) (xy 359.214166 -335.420208)
				(xy 359.375202 -335.420208)
			)
		)
	)
	(zone
		(layer "F.Cu")
		(hatch none 0.5)
		(connect_pads
			(clearance 0)
		)
		(min_thickness 0.25)
		(keepout
			(tracks allowed)
			(vias allowed)
			(pads allowed)
			(copperpour allowed)
			(footprints allowed)
		)
		(placement
			(enabled no)
			(sheetname "")
		)
		(fill
			(thermal_gap 0.5)
			(thermal_bridge_width 0.5)
			(island_removal_mode 0)
		)
		(polygon
			(pts
				(xy 420.615364 -20.04822) (xy 420.615364 -16.913606) (xy 422.394126 -16.913606) (xy 422.394126 -20.04822)
			)
		)
	)
	(zone
		(layer "F.Cu")
		(hatch none 0.5)
		(connect_pads
			(clearance 0)
		)
		(min_thickness 0.25)
		(keepout
			(tracks allowed)
			(vias allowed)
			(pads allowed)
			(copperpour allowed)
			(footprints allowed)
		)
		(placement
			(enabled no)
			(sheetname "")
		)
		(fill
			(thermal_gap 0.5)
			(thermal_bridge_width 0.5)
			(island_removal_mode 0)
		)
		(polygon
			(pts
				(xy 165.335458 -295.604946) (xy 165.335458 -295.376346) (xy 167.367458 -295.376346) (xy 167.367458 -295.604946)
			)
		)
	)
	(zone
		(layer "F.Cu")
		(hatch none 0.5)
		(connect_pads
			(clearance 0)
		)
		(min_thickness 0.25)
		(keepout
			(tracks not_allowed)
			(vias allowed)
			(pads allowed)
			(copperpour not_allowed)
			(footprints allowed)
		)
		(placement
			(enabled no)
			(sheetname "")
		)
		(fill
			(thermal_gap 0.5)
			(thermal_bridge_width 0.5)
			(island_removal_mode 0)
		)
		(polygon
			(pts
				(arc
					(start 72.282812 -47.049944)
					(mid 70.382892 -48.949864)
					(end 68.482972 -47.049944)
				)
				(arc
					(start 68.482972 -47.049944)
					(mid 70.382892 -45.150024)
					(end 72.282812 -47.049944)
				)
			)
		)
	)
	(zone
		(layer "F.Cu")
		(hatch none 0.5)
		(connect_pads
			(clearance 0)
		)
		(min_thickness 0.25)
		(keepout
			(tracks allowed)
			(vias allowed)
			(pads allowed)
			(copperpour allowed)
			(footprints allowed)
		)
		(placement
			(enabled no)
			(sheetname "")
		)
		(fill
			(thermal_gap 0.5)
			(thermal_bridge_width 0.5)
			(island_removal_mode 0)
		)
		(polygon
			(pts
				(xy 279.912826 -239.616488) (xy 277.58771 -239.616488) (xy 277.45309 -239.616488) (xy 277.45309 -238.667036)
				(xy 279.98166 -238.667036) (xy 279.98166 -239.616488)
			)
		)
	)
	(zone
		(layer "F.Cu")
		(hatch none 0.5)
		(connect_pads
			(clearance 0)
		)
		(min_thickness 0.25)
		(keepout
			(tracks allowed)
			(vias allowed)
			(pads allowed)
			(copperpour allowed)
			(footprints allowed)
		)
		(placement
			(enabled no)
			(sheetname "")
		)
		(fill
			(thermal_gap 0.5)
			(thermal_bridge_width 0.5)
			(island_removal_mode 0)
		)
		(polygon
			(pts
				(xy 207.154526 -214.626444) (xy 209.186526 -214.626444) (xy 209.186526 -214.855044) (xy 207.154526 -214.855044)
				(xy 207.018382 -214.855044) (xy 206.971392 -214.855044) (xy 206.971392 -214.626444) (xy 207.018382 -214.626444)
			)
		)
	)
	(zone
		(layer "F.Cu")
		(hatch none 0.5)
		(connect_pads
			(clearance 0)
		)
		(min_thickness 0.25)
		(keepout
			(tracks allowed)
			(vias allowed)
			(pads allowed)
			(copperpour allowed)
			(footprints allowed)
		)
		(placement
			(enabled no)
			(sheetname "")
		)
		(fill
			(thermal_gap 0.5)
			(thermal_bridge_width 0.5)
			(island_removal_mode 0)
		)
		(polygon
			(pts
				(xy 41.29151 -271.066514) (xy 41.29151 -270.622776) (xy 43.616626 -270.622776) (xy 43.616626 -271.066514)
			)
		)
	)
	(zone
		(layer "F.Cu")
		(hatch none 0.5)
		(connect_pads
			(clearance 0)
		)
		(min_thickness 0.25)
		(keepout
			(tracks allowed)
			(vias allowed)
			(pads allowed)
			(copperpour allowed)
			(footprints allowed)
		)
		(placement
			(enabled no)
			(sheetname "")
		)
		(fill
			(thermal_gap 0.5)
			(thermal_bridge_width 0.5)
			(island_removal_mode 0)
		)
		(polygon
			(pts
				(xy 180.423058 -220.804994) (xy 180.423058 -220.576394) (xy 182.455058 -220.576394) (xy 182.455058 -220.804994)
			)
		)
	)
	(zone
		(layer "F.Cu")
		(hatch none 0.5)
		(connect_pads
			(clearance 0)
		)
		(min_thickness 0.25)
		(keepout
			(tracks allowed)
			(vias allowed)
			(pads allowed)
			(copperpour allowed)
			(footprints allowed)
		)
		(placement
			(enabled no)
			(sheetname "")
		)
		(fill
			(thermal_gap 0.5)
			(thermal_bridge_width 0.5)
			(island_removal_mode 0)
		)
		(polygon
			(pts
				(xy 44.735242 -247.26646) (xy 44.735242 -246.822722) (xy 47.060358 -246.822722) (xy 47.060358 -247.26646)
			)
		)
	)
	(zone
		(layer "F.Cu")
		(hatch none 0.5)
		(connect_pads
			(clearance 0)
		)
		(min_thickness 0.25)
		(keepout
			(tracks allowed)
			(vias allowed)
			(pads allowed)
			(copperpour allowed)
			(footprints allowed)
		)
		(placement
			(enabled no)
			(sheetname "")
		)
		(fill
			(thermal_gap 0.5)
			(thermal_bridge_width 0.5)
			(island_removal_mode 0)
		)
		(polygon
			(pts
				(xy 277.58771 -283.816552) (xy 277.58771 -283.372814) (xy 279.912826 -283.372814) (xy 279.912826 -283.816552)
			)
		)
	)
	(zone
		(layer "F.Cu")
		(hatch none 0.5)
		(connect_pads
			(clearance 0)
		)
		(min_thickness 0.25)
		(keepout
			(tracks allowed)
			(vias allowed)
			(pads allowed)
			(copperpour allowed)
			(footprints not_allowed)
		)
		(placement
			(enabled no)
			(sheetname "")
		)
		(fill
			(thermal_gap 0.5)
			(thermal_bridge_width 0.5)
			(island_removal_mode 0)
		)
		(polygon
			(pts
				(arc
					(start 283.979874 -419.999922)
					(mid 287.98012 -415.999676)
					(end 291.980112 -419.999922)
				)
				(arc
					(start 291.980112 -419.999922)
					(mid 287.98012 -423.999914)
					(end 283.979874 -419.999922)
				)
			)
		)
	)
	(zone
		(layer "F.Cu")
		(hatch none 0.5)
		(connect_pads
			(clearance 0)
		)
		(min_thickness 0.25)
		(keepout
			(tracks allowed)
			(vias allowed)
			(pads allowed)
			(copperpour allowed)
			(footprints allowed)
		)
		(placement
			(enabled no)
			(sheetname "")
		)
		(fill
			(thermal_gap 0.5)
			(thermal_bridge_width 0.5)
			(island_removal_mode 0)
		)
		(polygon
			(pts
				(xy 259.056378 -241.31651) (xy 259.056378 -240.872772) (xy 261.381494 -240.872772) (xy 261.381494 -241.31651)
			)
		)
	)
	(zone
		(layer "F.Cu")
		(hatch none 0.5)
		(connect_pads
			(clearance 0)
		)
		(min_thickness 0.25)
		(keepout
			(tracks allowed)
			(vias allowed)
			(pads allowed)
			(copperpour allowed)
			(footprints allowed)
		)
		(placement
			(enabled no)
			(sheetname "")
		)
		(fill
			(thermal_gap 0.5)
			(thermal_bridge_width 0.5)
			(island_removal_mode 0)
		)
		(polygon
			(pts
				(xy 259.056378 -294.01643) (xy 259.056378 -293.572692) (xy 261.381494 -293.572692) (xy 261.381494 -294.01643)
			)
		)
	)
	(zone
		(layer "F.Cu")
		(hatch none 0.5)
		(connect_pads
			(clearance 0)
		)
		(min_thickness 0.25)
		(keepout
			(tracks allowed)
			(vias allowed)
			(pads allowed)
			(copperpour allowed)
			(footprints allowed)
		)
		(placement
			(enabled no)
			(sheetname "")
		)
		(fill
			(thermal_gap 0.5)
			(thermal_bridge_width 0.5)
			(island_removal_mode 0)
		)
		(polygon
			(pts
				(xy 259.056378 -228.566472) (xy 259.056378 -228.122734) (xy 261.381494 -228.122734) (xy 261.381494 -228.566472)
			)
		)
	)
	(zone
		(layer "F.Cu")
		(hatch none 0.5)
		(connect_pads
			(clearance 0)
		)
		(min_thickness 0.25)
		(keepout
			(tracks allowed)
			(vias allowed)
			(pads allowed)
			(copperpour allowed)
			(footprints allowed)
		)
		(placement
			(enabled no)
			(sheetname "")
		)
		(fill
			(thermal_gap 0.5)
			(thermal_bridge_width 0.5)
			(island_removal_mode 0)
		)
		(polygon
			(pts
				(xy 180.423058 -227.604828) (xy 180.423058 -227.376228) (xy 182.455058 -227.376228) (xy 182.455058 -227.604828)
			)
		)
	)
	(zone
		(layer "F.Cu")
		(hatch none 0.5)
		(connect_pads
			(clearance 0)
		)
		(min_thickness 0.25)
		(keepout
			(tracks allowed)
			(vias allowed)
			(pads allowed)
			(copperpour allowed)
			(footprints allowed)
		)
		(placement
			(enabled no)
			(sheetname "")
		)
		(fill
			(thermal_gap 0.5)
			(thermal_bridge_width 0.5)
			(island_removal_mode 0)
		)
		(polygon
			(pts
				(xy 161.891726 -223.976438) (xy 163.923726 -223.976438) (xy 163.923726 -224.205038) (xy 161.891726 -224.205038)
				(xy 161.755582 -224.205038) (xy 161.708592 -224.205038) (xy 161.708592 -223.976438) (xy 161.755582 -223.976438)
			)
		)
	)
	(zone
		(layer "F.Cu")
		(hatch none 0.5)
		(connect_pads
			(clearance 0)
		)
		(min_thickness 0.25)
		(keepout
			(tracks allowed)
			(vias allowed)
			(pads allowed)
			(copperpour allowed)
			(footprints allowed)
		)
		(placement
			(enabled no)
			(sheetname "")
		)
		(fill
			(thermal_gap 0.5)
			(thermal_bridge_width 0.5)
			(island_removal_mode 0)
		)
		(polygon
			(pts
				(xy 192.066926 -222.276416) (xy 194.098926 -222.276416) (xy 194.098926 -222.505016) (xy 192.066926 -222.505016)
				(xy 191.930782 -222.505016) (xy 191.883792 -222.505016) (xy 191.883792 -222.276416) (xy 191.930782 -222.276416)
			)
		)
	)
	(zone
		(layer "F.Cu")
		(hatch none 0.5)
		(connect_pads
			(clearance 0)
		)
		(min_thickness 0.25)
		(keepout
			(tracks allowed)
			(vias allowed)
			(pads allowed)
			(copperpour allowed)
			(footprints allowed)
		)
		(placement
			(enabled no)
			(sheetname "")
		)
		(fill
			(thermal_gap 0.5)
			(thermal_bridge_width 0.5)
			(island_removal_mode 0)
		)
		(polygon
			(pts
				(xy 304.319432 -210.716368) (xy 304.319432 -210.27263) (xy 306.644548 -210.27263) (xy 306.644548 -210.716368)
			)
		)
	)
	(zone
		(layer "F.Cu")
		(hatch none 0.5)
		(connect_pads
			(clearance 0)
		)
		(min_thickness 0.25)
		(keepout
			(tracks allowed)
			(vias allowed)
			(pads allowed)
			(copperpour allowed)
			(footprints allowed)
		)
		(placement
			(enabled no)
			(sheetname "")
		)
		(fill
			(thermal_gap 0.5)
			(thermal_bridge_width 0.5)
			(island_removal_mode 0)
		)
		(polygon
			(pts
				(xy 192.066926 -289.426396) (xy 194.098926 -289.426396) (xy 194.098926 -289.654996) (xy 192.066926 -289.654996)
				(xy 191.930782 -289.654996) (xy 191.883792 -289.654996) (xy 191.883792 -289.426396) (xy 191.930782 -289.426396)
			)
		)
	)
	(zone
		(layer "F.Cu")
		(hatch none 0.5)
		(connect_pads
			(clearance 0)
		)
		(min_thickness 0.25)
		(keepout
			(tracks allowed)
			(vias allowed)
			(pads allowed)
			(copperpour allowed)
			(footprints allowed)
		)
		(placement
			(enabled no)
			(sheetname "")
		)
		(fill
			(thermal_gap 0.5)
			(thermal_bridge_width 0.5)
			(island_removal_mode 0)
		)
		(polygon
			(pts
				(xy 180.423058 -299.00499) (xy 180.423058 -298.77639) (xy 182.455058 -298.77639) (xy 182.455058 -299.00499)
			)
		)
	)
	(zone
		(layer "F.Cu")
		(hatch none 0.5)
		(connect_pads
			(clearance 0)
		)
		(min_thickness 0.25)
		(keepout
			(tracks allowed)
			(vias allowed)
			(pads allowed)
			(copperpour allowed)
			(footprints allowed)
		)
		(placement
			(enabled no)
			(sheetname "")
		)
		(fill
			(thermal_gap 0.5)
			(thermal_bridge_width 0.5)
			(island_removal_mode 0)
		)
		(polygon
			(pts
				(xy 333.69758 -287.373568) (xy 333.9846 -287.373568) (xy 334.01508 -287.343088) (xy 334.01508 -286.715708)
				(xy 333.92872 -286.629348) (xy 333.74076 -286.629348) (xy 333.6671 -286.703008) (xy 333.6671 -287.343088)
			)
		)
	)
	(zone
		(layer "F.Cu")
		(hatch none 0.5)
		(connect_pads
			(clearance 0)
		)
		(min_thickness 0.25)
		(keepout
			(tracks not_allowed)
			(vias allowed)
			(pads allowed)
			(copperpour not_allowed)
			(footprints allowed)
		)
		(placement
			(enabled no)
			(sheetname "")
		)
		(fill
			(thermal_gap 0.5)
			(thermal_bridge_width 0.5)
			(island_removal_mode 0)
		)
		(polygon
			(pts
				(arc
					(start 356.125018 -431.360072)
					(mid 359.774998 -427.710092)
					(end 363.424978 -431.360072)
				)
				(arc
					(start 363.424978 -431.360072)
					(mid 359.774998 -435.010052)
					(end 356.125018 -431.360072)
				)
			)
		)
	)
	(zone
		(layer "F.Cu")
		(hatch none 0.5)
		(connect_pads
			(clearance 0)
		)
		(min_thickness 0.25)
		(keepout
			(tracks allowed)
			(vias allowed)
			(pads allowed)
			(copperpour allowed)
			(footprints allowed)
		)
		(placement
			(enabled no)
			(sheetname "")
		)
		(fill
			(thermal_gap 0.5)
			(thermal_bridge_width 0.5)
			(island_removal_mode 0)
		)
		(polygon
			(pts
				(xy 197.553834 -241.207036) (xy 195.521834 -241.207036) (xy 195.521834 -241.20475) (xy 195.343018 -241.20475)
				(xy 195.343018 -240.967514) (xy 195.205096 -240.967514) (xy 195.161916 -240.924334) (xy 195.161916 -240.791492)
				(xy 195.161916 -240.487454) (xy 195.23456 -240.41481) (xy 197.774814 -240.41481) (xy 197.916038 -240.556034)
				(xy 197.916038 -240.753138) (xy 197.834504 -240.834672) (xy 197.834504 -241.207036) (xy 197.736968 -241.207036)
				(xy 197.689978 -241.207036)
			)
		)
	)
	(zone
		(layer "F.Cu")
		(hatch none 0.5)
		(connect_pads
			(clearance 0)
		)
		(min_thickness 0.25)
		(keepout
			(tracks allowed)
			(vias allowed)
			(pads allowed)
			(copperpour allowed)
			(footprints allowed)
		)
		(placement
			(enabled no)
			(sheetname "")
		)
		(fill
			(thermal_gap 0.5)
			(thermal_bridge_width 0.5)
			(island_removal_mode 0)
		)
		(polygon
			(pts
				(xy 274.143978 -202.216512) (xy 274.143978 -201.772774) (xy 276.469094 -201.772774) (xy 276.469094 -202.216512)
			)
		)
	)
	(zone
		(layer "F.Cu")
		(hatch none 0.5)
		(connect_pads
			(clearance 0)
		)
		(min_thickness 0.25)
		(keepout
			(tracks allowed)
			(vias allowed)
			(pads allowed)
			(copperpour allowed)
			(footprints allowed)
		)
		(placement
			(enabled no)
			(sheetname "")
		)
		(fill
			(thermal_gap 0.5)
			(thermal_bridge_width 0.5)
			(island_removal_mode 0)
		)
		(polygon
			(pts
				(xy 292.67531 -305.916584) (xy 292.67531 -305.472846) (xy 295.000426 -305.472846) (xy 295.000426 -305.916584)
			)
		)
	)
	(zone
		(layer "F.Cu")
		(hatch none 0.5)
		(connect_pads
			(clearance 0)
		)
		(min_thickness 0.25)
		(keepout
			(tracks allowed)
			(vias allowed)
			(pads allowed)
			(copperpour allowed)
			(footprints allowed)
		)
		(placement
			(enabled no)
			(sheetname "")
		)
		(fill
			(thermal_gap 0.5)
			(thermal_bridge_width 0.5)
			(island_removal_mode 0)
		)
		(polygon
			(pts
				(xy 210.598258 -292.204902) (xy 210.598258 -291.976302) (xy 212.630258 -291.976302) (xy 212.630258 -292.204902)
			)
		)
	)
	(zone
		(layer "F.Cu")
		(hatch none 0.5)
		(connect_pads
			(clearance 0)
		)
		(min_thickness 0.25)
		(keepout
			(tracks allowed)
			(vias allowed)
			(pads allowed)
			(copperpour allowed)
			(footprints allowed)
		)
		(placement
			(enabled no)
			(sheetname "")
		)
		(fill
			(thermal_gap 0.5)
			(thermal_bridge_width 0.5)
			(island_removal_mode 0)
		)
		(polygon
			(pts
				(xy 304.319178 -231.966516) (xy 304.319178 -231.522778) (xy 306.644294 -231.522778) (xy 306.644294 -231.966516)
			)
		)
	)
	(zone
		(layer "F.Cu")
		(hatch none 0.5)
		(connect_pads
			(clearance 0)
		)
		(min_thickness 0.25)
		(keepout
			(tracks allowed)
			(vias allowed)
			(pads allowed)
			(copperpour allowed)
			(footprints allowed)
		)
		(placement
			(enabled no)
			(sheetname "")
		)
		(fill
			(thermal_gap 0.5)
			(thermal_bridge_width 0.5)
			(island_removal_mode 0)
		)
		(polygon
			(pts
				(xy 386.845556 -263.156192) (xy 387.048502 -263.359138) (xy 387.091428 -263.359138) (xy 387.535166 -262.915654)
				(xy 387.535166 -262.79348) (xy 387.402324 -262.660384) (xy 387.298184 -262.660384) (xy 386.845556 -263.113012)
			)
		)
	)
	(zone
		(layer "F.Cu")
		(hatch none 0.5)
		(connect_pads
			(clearance 0)
		)
		(min_thickness 0.25)
		(keepout
			(tracks allowed)
			(vias allowed)
			(pads allowed)
			(copperpour allowed)
			(footprints not_allowed)
		)
		(placement
			(enabled no)
			(sheetname "")
		)
		(fill
			(thermal_gap 0.5)
			(thermal_bridge_width 0.5)
			(island_removal_mode 0)
		)
		(polygon
			(pts
				(xy 231.30002 -38.595046) (xy 231.30002 -62.524894) (xy 237.300008 -62.524894) (xy 237.300008 -38.595046)
			)
		)
	)
	(zone
		(layer "F.Cu")
		(hatch none 0.5)
		(connect_pads
			(clearance 0)
		)
		(min_thickness 0.25)
		(keepout
			(tracks allowed)
			(vias allowed)
			(pads allowed)
			(copperpour allowed)
			(footprints allowed)
		)
		(placement
			(enabled no)
			(sheetname "")
		)
		(fill
			(thermal_gap 0.5)
			(thermal_bridge_width 0.5)
			(island_removal_mode 0)
		)
		(polygon
			(pts
				(xy 53.15839 -176.86909) (xy 53.15839 -173.33341) (xy 55.24119 -173.33341) (xy 55.24119 -176.86909)
			)
		)
	)
	(zone
		(layer "F.Cu")
		(hatch none 0.5)
		(connect_pads
			(clearance 0)
		)
		(min_thickness 0.25)
		(keepout
			(tracks allowed)
			(vias allowed)
			(pads allowed)
			(copperpour allowed)
			(footprints allowed)
		)
		(placement
			(enabled no)
			(sheetname "")
		)
		(fill
			(thermal_gap 0.5)
			(thermal_bridge_width 0.5)
			(island_removal_mode 0)
		)
		(polygon
			(pts
				(xy 29.647642 -225.166428) (xy 29.647642 -224.72269) (xy 31.972758 -224.72269) (xy 31.972758 -225.166428)
			)
		)
	)
	(zone
		(layer "F.Cu")
		(hatch none 0.5)
		(connect_pads
			(clearance 0)
		)
		(min_thickness 0.25)
		(keepout
			(tracks allowed)
			(vias allowed)
			(pads allowed)
			(copperpour allowed)
			(footprints allowed)
		)
		(placement
			(enabled no)
			(sheetname "")
		)
		(fill
			(thermal_gap 0.5)
			(thermal_bridge_width 0.5)
			(island_removal_mode 0)
		)
		(polygon
			(pts
				(xy 210.598258 -231.85501) (xy 210.598258 -231.62641) (xy 212.630258 -231.62641) (xy 212.630258 -231.85501)
			)
		)
	)
	(zone
		(layer "F.Cu")
		(hatch none 0.5)
		(connect_pads
			(clearance 0)
		)
		(min_thickness 0.25)
		(keepout
			(tracks allowed)
			(vias allowed)
			(pads allowed)
			(copperpour allowed)
			(footprints allowed)
		)
		(placement
			(enabled no)
			(sheetname "")
		)
		(fill
			(thermal_gap 0.5)
			(thermal_bridge_width 0.5)
			(island_removal_mode 0)
		)
		(polygon
			(pts
				(xy 428.363126 -278.60498) (xy 428.363126 -278.37638) (xy 430.395126 -278.37638) (xy 430.395126 -278.60498)
			)
		)
	)
	(zone
		(layer "F.Cu")
		(hatch none 0.5)
		(connect_pads
			(clearance 0)
		)
		(min_thickness 0.25)
		(keepout
			(tracks allowed)
			(vias allowed)
			(pads allowed)
			(copperpour allowed)
			(footprints allowed)
		)
		(placement
			(enabled no)
			(sheetname "")
		)
		(fill
			(thermal_gap 0.5)
			(thermal_bridge_width 0.5)
			(island_removal_mode 0)
		)
		(polygon
			(pts
				(xy 311.91708 -200.51649) (xy 311.91708 -200.072752) (xy 314.17768 -200.072752) (xy 314.17768 -200.51649)
			)
		)
	)
	(zone
		(layer "F.Cu")
		(hatch none 0.5)
		(connect_pads
			(clearance 0)
		)
		(min_thickness 0.25)
		(keepout
			(tracks allowed)
			(vias allowed)
			(pads allowed)
			(copperpour allowed)
			(footprints allowed)
		)
		(placement
			(enabled no)
			(sheetname "")
		)
		(fill
			(thermal_gap 0.5)
			(thermal_bridge_width 0.5)
			(island_removal_mode 0)
		)
		(polygon
			(pts
				(xy 279.912826 -274.466558) (xy 277.58771 -274.466558) (xy 277.456392 -274.466558) (xy 277.456392 -273.260566)
				(xy 279.96515 -273.260566) (xy 279.96515 -274.466558)
			)
		)
	)
	(zone
		(layer "F.Cu")
		(hatch none 0.5)
		(connect_pads
			(clearance 0)
		)
		(min_thickness 0.25)
		(keepout
			(tracks allowed)
			(vias allowed)
			(pads allowed)
			(copperpour allowed)
			(footprints allowed)
		)
		(placement
			(enabled no)
			(sheetname "")
		)
		(fill
			(thermal_gap 0.5)
			(thermal_bridge_width 0.5)
			(island_removal_mode 0)
		)
		(polygon
			(pts
				(xy 405.731726 -273.276314) (xy 407.763726 -273.276314) (xy 407.763726 -273.2786) (xy 407.901648 -273.2786)
				(xy 407.901648 -273.559016) (xy 407.901648 -274.06854) (xy 405.99106 -274.06854) (xy 405.99106 -274.354036)
				(xy 405.527764 -274.354036) (xy 405.45512 -274.354036) (xy 405.45512 -273.276314) (xy 405.527764 -273.276314)
				(xy 405.609044 -273.276314)
			)
		)
	)
	(zone
		(layer "F.Cu")
		(hatch none 0.5)
		(connect_pads
			(clearance 0)
		)
		(min_thickness 0.25)
		(keepout
			(tracks allowed)
			(vias allowed)
			(pads allowed)
			(copperpour allowed)
			(footprints allowed)
		)
		(placement
			(enabled no)
			(sheetname "")
		)
		(fill
			(thermal_gap 0.5)
			(thermal_bridge_width 0.5)
			(island_removal_mode 0)
		)
		(polygon
			(pts
				(xy 440.006994 -228.456998) (xy 442.038994 -228.456998) (xy 442.038994 -228.228398) (xy 440.006994 -228.228398)
				(xy 439.875676 -228.228398) (xy 439.849768 -228.228398) (xy 439.849768 -228.456998) (xy 439.875676 -228.456998)
			)
		)
	)
	(zone
		(layer "F.Cu")
		(hatch none 0.5)
		(connect_pads
			(clearance 0)
		)
		(min_thickness 0.25)
		(keepout
			(tracks allowed)
			(vias allowed)
			(pads allowed)
			(copperpour allowed)
			(footprints allowed)
		)
		(placement
			(enabled no)
			(sheetname "")
		)
		(fill
			(thermal_gap 0.5)
			(thermal_bridge_width 0.5)
			(island_removal_mode 0)
		)
		(polygon
			(pts
				(xy 326.41794 -330.558648) (xy 326.41794 -328.257408) (xy 330.78928 -328.257408) (xy 330.78928 -330.558648)
			)
		)
	)
	(zone
		(layer "F.Cu")
		(hatch none 0.5)
		(connect_pads
			(clearance 0)
		)
		(min_thickness 0.25)
		(keepout
			(tracks allowed)
			(vias allowed)
			(pads allowed)
			(copperpour allowed)
			(footprints allowed)
		)
		(placement
			(enabled no)
			(sheetname "")
		)
		(fill
			(thermal_gap 0.5)
			(thermal_bridge_width 0.5)
			(island_removal_mode 0)
		)
		(polygon
			(pts
				(xy 455.094594 -315.776356) (xy 457.126594 -315.776356) (xy 457.126594 -316.004956) (xy 455.094594 -316.004956)
				(xy 454.95845 -316.004956) (xy 454.91146 -316.004956) (xy 454.91146 -315.776356) (xy 454.95845 -315.776356)
			)
		)
	)
	(zone
		(layer "F.Cu")
		(hatch none 0.5)
		(connect_pads
			(clearance 0)
		)
		(min_thickness 0.25)
		(keepout
			(tracks allowed)
			(vias allowed)
			(pads allowed)
			(copperpour allowed)
			(footprints allowed)
		)
		(placement
			(enabled no)
			(sheetname "")
		)
		(fill
			(thermal_gap 0.5)
			(thermal_bridge_width 0.5)
			(island_removal_mode 0)
		)
		(polygon
			(pts
				(xy 157.740858 -197.958202) (xy 157.740858 -197.551802) (xy 159.899858 -197.551802) (xy 159.899858 -197.958202)
			)
		)
	)
	(zone
		(layer "F.Cu")
		(hatch none 0.5)
		(connect_pads
			(clearance 0)
		)
		(min_thickness 0.25)
		(keepout
			(tracks allowed)
			(vias allowed)
			(pads allowed)
			(copperpour allowed)
			(footprints allowed)
		)
		(placement
			(enabled no)
			(sheetname "")
		)
		(fill
			(thermal_gap 0.5)
			(thermal_bridge_width 0.5)
			(island_removal_mode 0)
		)
		(polygon
			(pts
				(xy 440.006994 -303.25695) (xy 442.038994 -303.25695) (xy 442.038994 -303.02835) (xy 440.006994 -303.02835)
				(xy 439.875676 -303.02835) (xy 439.849768 -303.02835) (xy 439.849768 -303.25695) (xy 439.875676 -303.25695)
			)
		)
	)
	(zone
		(layer "F.Cu")
		(hatch none 0.5)
		(connect_pads
			(clearance 0)
		)
		(min_thickness 0.25)
		(keepout
			(tracks allowed)
			(vias allowed)
			(pads allowed)
			(copperpour allowed)
			(footprints allowed)
		)
		(placement
			(enabled no)
			(sheetname "")
		)
		(fill
			(thermal_gap 0.5)
			(thermal_bridge_width 0.5)
			(island_removal_mode 0)
		)
		(polygon
			(pts
				(xy 304.319178 -224.316544) (xy 304.319178 -223.872806) (xy 306.644294 -223.872806) (xy 306.644294 -224.316544)
			)
		)
	)
	(zone
		(layer "F.Cu")
		(hatch none 0.5)
		(connect_pads
			(clearance 0)
		)
		(min_thickness 0.25)
		(keepout
			(tracks allowed)
			(vias allowed)
			(pads allowed)
			(copperpour allowed)
			(footprints allowed)
		)
		(placement
			(enabled no)
			(sheetname "")
		)
		(fill
			(thermal_gap 0.5)
			(thermal_bridge_width 0.5)
			(island_removal_mode 0)
		)
		(polygon
			(pts
				(xy 405.731726 -308.354984) (xy 405.731726 -308.126384) (xy 407.763726 -308.126384) (xy 407.763726 -308.354984)
			)
		)
	)
	(zone
		(layer "F.Cu")
		(hatch none 0.5)
		(connect_pads
			(clearance 0)
		)
		(min_thickness 0.25)
		(keepout
			(tracks allowed)
			(vias allowed)
			(pads allowed)
			(copperpour allowed)
			(footprints allowed)
		)
		(placement
			(enabled no)
			(sheetname "")
		)
		(fill
			(thermal_gap 0.5)
			(thermal_bridge_width 0.5)
			(island_removal_mode 0)
		)
		(polygon
			(pts
				(xy 180.423058 -276.904958) (xy 180.423058 -276.676358) (xy 182.455058 -276.676358) (xy 182.455058 -276.904958)
			)
		)
	)
	(zone
		(layer "F.Cu")
		(hatch none 0.5)
		(connect_pads
			(clearance 0)
		)
		(min_thickness 0.25)
		(keepout
			(tracks allowed)
			(vias allowed)
			(pads allowed)
			(copperpour allowed)
			(footprints not_allowed)
		)
		(placement
			(enabled no)
			(sheetname "")
		)
		(fill
			(thermal_gap 0.5)
			(thermal_bridge_width 0.5)
			(island_removal_mode 0)
		)
		(polygon
			(pts
				(arc
					(start 85.858604 -333.424276)
					(mid 84.939385 -333.805029)
					(end 84.558632 -334.724248)
				)
				(xy 84.558632 -339.214968)
				(arc
					(start 77.22489 -339.214968)
					(mid 76.305671 -339.595721)
					(end 75.924918 -340.51494)
				)
				(xy 75.924918 -348.836488) (xy 87.908638 -348.836488) (xy 87.908638 -345.424252)
				(arc
					(start 92.639642 -345.424252)
					(mid 93.558861 -345.043499)
					(end 93.939614 -344.12428)
				)
				(xy 93.939614 -339.691472) (xy 125.021594 -339.691472)
				(arc
					(start 125.021594 -344.12428)
					(mid 125.402347 -345.043499)
					(end 126.321566 -345.424252)
				)
				(xy 130.48107 -345.424252) (xy 130.48107 -348.836488) (xy 142.54861 -348.836488)
				(arc
					(start 142.54861 -340.51494)
					(mid 142.167857 -339.595721)
					(end 141.248638 -339.214968)
				)
				(xy 134.182104 -339.214968)
				(arc
					(start 134.182104 -334.724248)
					(mid 133.801351 -333.805029)
					(end 132.882132 -333.424276)
				)
				(xy 126.021592 -333.424276)
				(arc
					(start 126.021592 -331.314044)
					(mid 125.640839 -330.394825)
					(end 124.72162 -330.014072)
				)
				(arc
					(start 94.019116 -330.014072)
					(mid 93.099897 -330.394825)
					(end 92.719144 -331.314044)
				)
				(xy 92.719144 -333.424276)
			)
		)
	)
	(zone
		(layer "F.Cu")
		(hatch none 0.5)
		(connect_pads
			(clearance 0)
		)
		(min_thickness 0.25)
		(keepout
			(tracks allowed)
			(vias allowed)
			(pads allowed)
			(copperpour allowed)
			(footprints allowed)
		)
		(placement
			(enabled no)
			(sheetname "")
		)
		(fill
			(thermal_gap 0.5)
			(thermal_bridge_width 0.5)
			(island_removal_mode 0)
		)
		(polygon
			(pts
				(xy 259.056378 -213.266528) (xy 259.056378 -212.82279) (xy 261.381494 -212.82279) (xy 261.381494 -213.266528)
			)
		)
	)
	(zone
		(layer "F.Cu")
		(hatch none 0.5)
		(connect_pads
			(clearance 0)
		)
		(min_thickness 0.25)
		(keepout
			(tracks allowed)
			(vias allowed)
			(pads allowed)
			(copperpour allowed)
			(footprints allowed)
		)
		(placement
			(enabled no)
			(sheetname "")
		)
		(fill
			(thermal_gap 0.5)
			(thermal_bridge_width 0.5)
			(island_removal_mode 0)
		)
		(polygon
			(pts
				(xy 59.822842 -222.616522) (xy 59.822842 -222.172784) (xy 62.147958 -222.172784) (xy 62.147958 -222.616522)
			)
		)
	)
	(zone
		(layer "F.Cu")
		(hatch none 0.5)
		(connect_pads
			(clearance 0)
		)
		(min_thickness 0.25)
		(keepout
			(tracks allowed)
			(vias allowed)
			(pads allowed)
			(copperpour allowed)
			(footprints allowed)
		)
		(placement
			(enabled no)
			(sheetname "")
		)
		(fill
			(thermal_gap 0.5)
			(thermal_bridge_width 0.5)
			(island_removal_mode 0)
		)
		(polygon
			(pts
				(xy 428.363126 -270.955008) (xy 428.363126 -270.726408) (xy 430.395126 -270.726408) (xy 430.395126 -270.955008)
			)
		)
	)
	(zone
		(layer "F.Cu")
		(hatch none 0.5)
		(connect_pads
			(clearance 0)
		)
		(min_thickness 0.25)
		(keepout
			(tracks allowed)
			(vias allowed)
			(pads allowed)
			(copperpour allowed)
			(footprints allowed)
		)
		(placement
			(enabled no)
			(sheetname "")
		)
		(fill
			(thermal_gap 0.5)
			(thermal_bridge_width 0.5)
			(island_removal_mode 0)
		)
		(polygon
			(pts
				(xy 29.027882 -20.10791) (xy 29.027882 -16.973296) (xy 30.806644 -16.973296) (xy 30.806644 -20.10791)
			)
		)
	)
	(zone
		(layer "F.Cu")
		(hatch none 0.5)
		(connect_pads
			(clearance 0)
		)
		(min_thickness 0.25)
		(keepout
			(tracks allowed)
			(vias allowed)
			(pads allowed)
			(copperpour allowed)
			(footprints allowed)
		)
		(placement
			(enabled no)
			(sheetname "")
		)
		(fill
			(thermal_gap 0.5)
			(thermal_bridge_width 0.5)
			(island_removal_mode 0)
		)
		(polygon
			(pts
				(xy 428.363126 -218.254834) (xy 428.363126 -218.026234) (xy 430.395126 -218.026234) (xy 430.395126 -218.254834)
			)
		)
	)
	(zone
		(layer "F.Cu")
		(hatch none 0.5)
		(connect_pads
			(clearance 0)
		)
		(min_thickness 0.25)
		(keepout
			(tracks allowed)
			(vias allowed)
			(pads allowed)
			(copperpour allowed)
			(footprints allowed)
		)
		(placement
			(enabled no)
			(sheetname "")
		)
		(fill
			(thermal_gap 0.5)
			(thermal_bridge_width 0.5)
			(island_removal_mode 0)
		)
		(polygon
			(pts
				(xy 180.423058 -239.504982) (xy 180.423058 -239.276382) (xy 182.455058 -239.276382) (xy 182.455058 -239.504982)
			)
		)
	)
	(zone
		(layer "F.Cu")
		(hatch none 0.5)
		(connect_pads
			(clearance 0)
		)
		(min_thickness 0.25)
		(keepout
			(tracks allowed)
			(vias allowed)
			(pads allowed)
			(copperpour allowed)
			(footprints allowed)
		)
		(placement
			(enabled no)
			(sheetname "")
		)
		(fill
			(thermal_gap 0.5)
			(thermal_bridge_width 0.5)
			(island_removal_mode 0)
		)
		(polygon
			(pts
				(xy 262.50011 -293.166546) (xy 262.50011 -292.722808) (xy 264.825226 -292.722808) (xy 264.825226 -293.166546)
			)
		)
	)
	(zone
		(layer "F.Cu")
		(hatch none 0.5)
		(connect_pads
			(clearance 0)
		)
		(min_thickness 0.25)
		(keepout
			(tracks allowed)
			(vias allowed)
			(pads allowed)
			(copperpour allowed)
			(footprints allowed)
		)
		(placement
			(enabled no)
			(sheetname "")
		)
		(fill
			(thermal_gap 0.5)
			(thermal_bridge_width 0.5)
			(island_removal_mode 0)
		)
		(polygon
			(pts
				(xy 274.143978 -231.966516) (xy 274.143978 -231.522778) (xy 276.469094 -231.522778) (xy 276.469094 -231.966516)
			)
		)
	)
	(zone
		(layer "F.Cu")
		(hatch none 0.5)
		(connect_pads
			(clearance 0)
		)
		(min_thickness 0.25)
		(keepout
			(tracks allowed)
			(vias allowed)
			(pads allowed)
			(copperpour allowed)
			(footprints allowed)
		)
		(placement
			(enabled no)
			(sheetname "")
		)
		(fill
			(thermal_gap 0.5)
			(thermal_bridge_width 0.5)
			(island_removal_mode 0)
		)
		(polygon
			(pts
				(xy 356.62362 -41.01592) (xy 356.62362 -39.48176) (xy 355.60254 -39.48176) (xy 355.60254 -41.01592)
			)
		)
	)
	(zone
		(layer "F.Cu")
		(hatch none 0.5)
		(connect_pads
			(clearance 0)
		)
		(min_thickness 0.25)
		(keepout
			(tracks allowed)
			(vias allowed)
			(pads allowed)
			(copperpour allowed)
			(footprints not_allowed)
		)
		(placement
			(enabled no)
			(sheetname "")
		)
		(fill
			(thermal_gap 0.5)
			(thermal_bridge_width 0.5)
			(island_removal_mode 0)
		)
		(polygon
			(pts
				(xy 102.225094 -296.720006) (xy 121.635012 -296.720006) (xy 121.635012 -293.269924) (xy 102.225094 -293.269924)
			)
		)
	)
	(zone
		(layer "F.Cu")
		(hatch none 0.5)
		(connect_pads
			(clearance 0)
		)
		(min_thickness 0.25)
		(keepout
			(tracks allowed)
			(vias allowed)
			(pads allowed)
			(copperpour allowed)
			(footprints allowed)
		)
		(placement
			(enabled no)
			(sheetname "")
		)
		(fill
			(thermal_gap 0.5)
			(thermal_bridge_width 0.5)
			(island_removal_mode 0)
		)
		(polygon
			(pts
				(xy 259.056378 -269.366492) (xy 259.056378 -268.922754) (xy 261.381494 -268.922754) (xy 261.381494 -269.366492)
			)
		)
	)
	(zone
		(layer "F.Cu")
		(hatch none 0.5)
		(connect_pads
			(clearance 0)
		)
		(min_thickness 0.25)
		(keepout
			(tracks allowed)
			(vias allowed)
			(pads allowed)
			(copperpour allowed)
			(footprints allowed)
		)
		(placement
			(enabled no)
			(sheetname "")
		)
		(fill
			(thermal_gap 0.5)
			(thermal_bridge_width 0.5)
			(island_removal_mode 0)
		)
		(polygon
			(pts
				(xy 262.50011 -250.666504) (xy 262.50011 -250.222766) (xy 264.825226 -250.222766) (xy 264.825226 -250.666504)
			)
		)
	)
	(zone
		(layer "F.Cu")
		(hatch none 0.5)
		(connect_pads
			(clearance 0)
		)
		(min_thickness 0.25)
		(keepout
			(tracks allowed)
			(vias allowed)
			(pads allowed)
			(copperpour allowed)
			(footprints allowed)
		)
		(placement
			(enabled no)
			(sheetname "")
		)
		(fill
			(thermal_gap 0.5)
			(thermal_bridge_width 0.5)
			(island_removal_mode 0)
		)
		(polygon
			(pts
				(xy 26.20391 -289.766502) (xy 26.20391 -289.322764) (xy 28.529026 -289.322764) (xy 28.529026 -289.766502)
			)
		)
	)
	(zone
		(layer "F.Cu")
		(hatch none 0.5)
		(connect_pads
			(clearance 0)
		)
		(min_thickness 0.25)
		(keepout
			(tracks allowed)
			(vias allowed)
			(pads allowed)
			(copperpour allowed)
			(footprints allowed)
		)
		(placement
			(enabled no)
			(sheetname "")
		)
		(fill
			(thermal_gap 0.5)
			(thermal_bridge_width 0.5)
			(island_removal_mode 0)
		)
		(polygon
			(pts
				(xy 350.565212 -331.689456) (xy 350.565212 -335.695036) (xy 351.045272 -336.175096) (xy 353.110292 -336.175096)
				(xy 353.382072 -335.903316) (xy 353.382072 -334.049116) (xy 353.633532 -333.797656) (xy 355.553772 -333.797656)
				(xy 355.970332 -333.381096) (xy 355.970332 -331.890116) (xy 355.322632 -331.242416) (xy 351.012252 -331.242416)
			)
		)
	)
	(zone
		(layer "F.Cu")
		(hatch none 0.5)
		(connect_pads
			(clearance 0)
		)
		(min_thickness 0.25)
		(keepout
			(tracks allowed)
			(vias allowed)
			(pads allowed)
			(copperpour allowed)
			(footprints allowed)
		)
		(placement
			(enabled no)
			(sheetname "")
		)
		(fill
			(thermal_gap 0.5)
			(thermal_bridge_width 0.5)
			(island_removal_mode 0)
		)
		(polygon
			(pts
				(xy 332.177136 -229.285292) (xy 332.380082 -229.488238) (xy 332.423008 -229.488238) (xy 332.866746 -229.044754)
				(xy 332.866746 -228.92258) (xy 332.733904 -228.789484) (xy 332.629764 -228.789484) (xy 332.177136 -229.242112)
			)
		)
	)
	(zone
		(layer "F.Cu")
		(hatch none 0.5)
		(connect_pads
			(clearance 0)
		)
		(min_thickness 0.25)
		(keepout
			(tracks allowed)
			(vias allowed)
			(pads allowed)
			(copperpour allowed)
			(footprints allowed)
		)
		(placement
			(enabled no)
			(sheetname "")
		)
		(fill
			(thermal_gap 0.5)
			(thermal_bridge_width 0.5)
			(island_removal_mode 0)
		)
		(polygon
			(pts
				(xy 262.50011 -267.66647) (xy 262.50011 -267.222732) (xy 264.825226 -267.222732) (xy 264.825226 -267.66647)
			)
		)
	)
	(zone
		(layer "F.Cu")
		(hatch none 0.5)
		(connect_pads
			(clearance 0)
		)
		(min_thickness 0.25)
		(keepout
			(tracks allowed)
			(vias allowed)
			(pads allowed)
			(copperpour allowed)
			(footprints allowed)
		)
		(placement
			(enabled no)
			(sheetname "")
		)
		(fill
			(thermal_gap 0.5)
			(thermal_bridge_width 0.5)
			(island_removal_mode 0)
		)
		(polygon
			(pts
				(xy 405.731726 -217.40495) (xy 405.731726 -217.17635) (xy 407.763726 -217.17635) (xy 407.763726 -217.40495)
			)
		)
	)
	(zone
		(layer "F.Cu")
		(hatch none 0.5)
		(connect_pads
			(clearance 0)
		)
		(min_thickness 0.25)
		(keepout
			(tracks allowed)
			(vias allowed)
			(pads allowed)
			(copperpour allowed)
			(footprints allowed)
		)
		(placement
			(enabled no)
			(sheetname "")
		)
		(fill
			(thermal_gap 0.5)
			(thermal_bridge_width 0.5)
			(island_removal_mode 0)
		)
		(polygon
			(pts
				(xy 180.827934 -352.746564) (xy 179.011834 -352.746564) (xy 179.011834 -351.367344) (xy 180.827934 -351.367344)
			)
		)
	)
	(zone
		(layer "F.Cu")
		(hatch none 0.5)
		(connect_pads
			(clearance 0)
		)
		(min_thickness 0.25)
		(keepout
			(tracks allowed)
			(vias allowed)
			(pads allowed)
			(copperpour allowed)
			(footprints allowed)
		)
		(placement
			(enabled no)
			(sheetname "")
		)
		(fill
			(thermal_gap 0.5)
			(thermal_bridge_width 0.5)
			(island_removal_mode 0)
		)
		(polygon
			(pts
				(xy 11.11631 -267.66647) (xy 11.11631 -267.222732) (xy 13.441426 -267.222732) (xy 13.441426 -267.66647)
			)
		)
	)
	(zone
		(layer "F.Cu")
		(hatch none 0.5)
		(connect_pads
			(clearance 0)
		)
		(min_thickness 0.25)
		(keepout
			(tracks allowed)
			(vias allowed)
			(pads allowed)
			(copperpour allowed)
			(footprints allowed)
		)
		(placement
			(enabled no)
			(sheetname "")
		)
		(fill
			(thermal_gap 0.5)
			(thermal_bridge_width 0.5)
			(island_removal_mode 0)
		)
		(polygon
			(pts
				(xy 409.831794 -294.754808) (xy 409.831794 -294.526208) (xy 411.863794 -294.526208) (xy 411.863794 -294.754808)
			)
		)
	)
	(zone
		(layer "F.Cu")
		(hatch none 0.5)
		(connect_pads
			(clearance 0)
		)
		(min_thickness 0.25)
		(keepout
			(tracks allowed)
			(vias allowed)
			(pads allowed)
			(copperpour allowed)
			(footprints allowed)
		)
		(placement
			(enabled no)
			(sheetname "")
		)
		(fill
			(thermal_gap 0.5)
			(thermal_bridge_width 0.5)
			(island_removal_mode 0)
		)
		(polygon
			(pts
				(xy 29.647642 -283.816552) (xy 29.647642 -283.372814) (xy 31.972758 -283.372814) (xy 31.972758 -283.816552)
			)
		)
	)
	(zone
		(layer "F.Cu")
		(hatch none 0.5)
		(connect_pads
			(clearance 0)
		)
		(min_thickness 0.25)
		(keepout
			(tracks allowed)
			(vias allowed)
			(pads allowed)
			(copperpour allowed)
			(footprints allowed)
		)
		(placement
			(enabled no)
			(sheetname "")
		)
		(fill
			(thermal_gap 0.5)
			(thermal_bridge_width 0.5)
			(island_removal_mode 0)
		)
		(polygon
			(pts
				(xy 56.37911 -252.727206) (xy 56.37911 -251.922788) (xy 58.704226 -251.922788) (xy 58.704226 -252.727206)
			)
		)
	)
	(zone
		(layer "F.Cu")
		(hatch none 0.5)
		(connect_pads
			(clearance 0)
		)
		(min_thickness 0.25)
		(keepout
			(tracks not_allowed)
			(vias allowed)
			(pads allowed)
			(copperpour not_allowed)
			(footprints allowed)
		)
		(placement
			(enabled no)
			(sheetname "")
		)
		(fill
			(thermal_gap 0.5)
			(thermal_bridge_width 0.5)
			(island_removal_mode 0)
		)
		(polygon
			(pts
				(xy 375.53519 -339.670644) (xy 379.46838 -339.670644) (xy 379.46838 -339.569552) (xy 379.38456 -339.485732)
				(xy 377.923044 -339.485732) (xy 377.923044 -337.326732) (xy 380.079758 -337.326732) (xy 380.079758 -337.07705)
				(xy 377.73864 -337.07705) (xy 377.73864 -337.401408) (xy 377.631706 -337.401408) (xy 377.631706 -339.430106)
				(xy 375.777506 -339.430106) (xy 375.777506 -339.18906) (xy 375.53519 -339.18906)
			)
		)
	)
	(zone
		(layer "F.Cu")
		(hatch none 0.5)
		(connect_pads
			(clearance 0)
		)
		(min_thickness 0.25)
		(keepout
			(tracks allowed)
			(vias allowed)
			(pads allowed)
			(copperpour allowed)
			(footprints allowed)
		)
		(placement
			(enabled no)
			(sheetname "")
		)
		(fill
			(thermal_gap 0.5)
			(thermal_bridge_width 0.5)
			(island_removal_mode 0)
		)
		(polygon
			(pts
				(xy 11.11631 -300.816518) (xy 11.11631 -300.37278) (xy 13.441426 -300.37278) (xy 13.441426 -300.816518)
			)
		)
	)
	(zone
		(layer "F.Cu")
		(hatch none 0.5)
		(connect_pads
			(clearance 0)
		)
		(min_thickness 0.25)
		(keepout
			(tracks allowed)
			(vias allowed)
			(pads allowed)
			(copperpour allowed)
			(footprints allowed)
		)
		(placement
			(enabled no)
			(sheetname "")
		)
		(fill
			(thermal_gap 0.5)
			(thermal_bridge_width 0.5)
			(island_removal_mode 0)
		)
		(polygon
			(pts
				(xy 455.094594 -270.726408) (xy 457.126594 -270.726408) (xy 457.126594 -270.955008) (xy 455.094594 -270.955008)
				(xy 454.95845 -270.955008) (xy 454.91146 -270.955008) (xy 454.91146 -270.726408) (xy 454.95845 -270.726408)
			)
		)
	)
	(zone
		(layer "F.Cu")
		(hatch none 0.5)
		(connect_pads
			(clearance 0)
		)
		(min_thickness 0.25)
		(keepout
			(tracks allowed)
			(vias allowed)
			(pads allowed)
			(copperpour allowed)
			(footprints allowed)
		)
		(placement
			(enabled no)
			(sheetname "")
		)
		(fill
			(thermal_gap 0.5)
			(thermal_bridge_width 0.5)
			(island_removal_mode 0)
		)
		(polygon
			(pts
				(xy 455.094594 -197.626478) (xy 457.126594 -197.626478) (xy 457.126594 -197.855078) (xy 455.094594 -197.855078)
				(xy 454.95845 -197.855078) (xy 454.91146 -197.855078) (xy 454.91146 -197.626478) (xy 454.95845 -197.626478)
			)
		)
	)
	(zone
		(layer "F.Cu")
		(hatch none 0.5)
		(connect_pads
			(clearance 0)
		)
		(min_thickness 0.25)
		(keepout
			(tracks allowed)
			(vias allowed)
			(pads allowed)
			(copperpour allowed)
			(footprints allowed)
		)
		(placement
			(enabled no)
			(sheetname "")
		)
		(fill
			(thermal_gap 0.5)
			(thermal_bridge_width 0.5)
			(island_removal_mode 0)
		)
		(polygon
			(pts
				(xy 440.006994 -201.026268) (xy 442.038994 -201.026268) (xy 442.038994 -201.254868) (xy 440.006994 -201.254868)
				(xy 439.875676 -201.254868) (xy 439.849768 -201.254868) (xy 439.849768 -201.026268) (xy 439.875676 -201.026268)
			)
		)
	)
	(zone
		(layer "F.Cu")
		(hatch none 0.5)
		(connect_pads
			(clearance 0)
		)
		(min_thickness 0.25)
		(keepout
			(tracks allowed)
			(vias allowed)
			(pads allowed)
			(copperpour allowed)
			(footprints allowed)
		)
		(placement
			(enabled no)
			(sheetname "")
		)
		(fill
			(thermal_gap 0.5)
			(thermal_bridge_width 0.5)
			(island_removal_mode 0)
		)
		(polygon
			(pts
				(xy 423.75582 -12.703048) (xy 423.75582 -9.914128) (xy 431.73904 -9.914128) (xy 431.73904 -12.703048)
			)
		)
	)
	(zone
		(layer "F.Cu")
		(hatch none 0.5)
		(connect_pads
			(clearance 0)
		)
		(min_thickness 0.25)
		(keepout
			(tracks allowed)
			(vias allowed)
			(pads allowed)
			(copperpour allowed)
			(footprints allowed)
		)
		(placement
			(enabled no)
			(sheetname "")
		)
		(fill
			(thermal_gap 0.5)
			(thermal_bridge_width 0.5)
			(island_removal_mode 0)
		)
		(polygon
			(pts
				(xy 289.231578 -226.016566) (xy 289.231578 -225.572828) (xy 291.556694 -225.572828) (xy 291.556694 -226.016566)
			)
		)
	)
	(zone
		(layer "F.Cu")
		(hatch none 0.5)
		(connect_pads
			(clearance 0)
		)
		(min_thickness 0.25)
		(keepout
			(tracks allowed)
			(vias allowed)
			(pads allowed)
			(copperpour allowed)
			(footprints allowed)
		)
		(placement
			(enabled no)
			(sheetname "")
		)
		(fill
			(thermal_gap 0.5)
			(thermal_bridge_width 0.5)
			(island_removal_mode 0)
		)
		(polygon
			(pts
				(xy 413.275526 -302.405034) (xy 413.275526 -302.176434) (xy 415.307526 -302.176434) (xy 415.307526 -302.405034)
			)
		)
	)
	(zone
		(layer "F.Cu")
		(hatch none 0.5)
		(connect_pads
			(clearance 0)
		)
		(min_thickness 0.25)
		(keepout
			(tracks allowed)
			(vias allowed)
			(pads allowed)
			(copperpour allowed)
			(footprints allowed)
		)
		(placement
			(enabled no)
			(sheetname "")
		)
		(fill
			(thermal_gap 0.5)
			(thermal_bridge_width 0.5)
			(island_removal_mode 0)
		)
		(polygon
			(pts
				(xy 320.185542 -410.948886) (xy 320.185542 -406.105868) (xy 322.069968 -406.105868) (xy 322.069968 -410.948886)
			)
		)
	)
	(zone
		(layer "F.Cu")
		(hatch none 0.5)
		(connect_pads
			(clearance 0)
		)
		(min_thickness 0.25)
		(keepout
			(tracks allowed)
			(vias allowed)
			(pads allowed)
			(copperpour allowed)
			(footprints allowed)
		)
		(placement
			(enabled no)
			(sheetname "")
		)
		(fill
			(thermal_gap 0.5)
			(thermal_bridge_width 0.5)
			(island_removal_mode 0)
		)
		(polygon
			(pts
				(xy 136.54278 -287.393888) (xy 136.8298 -287.393888) (xy 136.86028 -287.363408) (xy 136.86028 -286.736028)
				(xy 136.77392 -286.649668) (xy 136.58596 -286.649668) (xy 136.5123 -286.723328) (xy 136.5123 -287.363408)
			)
		)
	)
	(zone
		(layer "F.Cu")
		(hatch none 0.5)
		(connect_pads
			(clearance 0)
		)
		(min_thickness 0.25)
		(keepout
			(tracks allowed)
			(vias allowed)
			(pads allowed)
			(copperpour allowed)
			(footprints allowed)
		)
		(placement
			(enabled no)
			(sheetname "")
		)
		(fill
			(thermal_gap 0.5)
			(thermal_bridge_width 0.5)
			(island_removal_mode 0)
		)
		(polygon
			(pts
				(xy 259.056378 -201.366628) (xy 259.056378 -200.92289) (xy 261.381494 -200.92289) (xy 261.381494 -201.366628)
			)
		)
	)
	(zone
		(layer "F.Cu")
		(hatch none 0.5)
		(connect_pads
			(clearance 0)
		)
		(min_thickness 0.25)
		(keepout
			(tracks allowed)
			(vias allowed)
			(pads allowed)
			(copperpour allowed)
			(footprints allowed)
		)
		(placement
			(enabled no)
			(sheetname "")
		)
		(fill
			(thermal_gap 0.5)
			(thermal_bridge_width 0.5)
			(island_removal_mode 0)
		)
		(polygon
			(pts
				(xy 29.647642 -245.566438) (xy 29.647642 -245.1227) (xy 31.972758 -245.1227) (xy 31.972758 -245.566438)
			)
		)
	)
	(zone
		(layer "F.Cu")
		(hatch none 0.5)
		(connect_pads
			(clearance 0)
		)
		(min_thickness 0.25)
		(keepout
			(tracks allowed)
			(vias allowed)
			(pads allowed)
			(copperpour allowed)
			(footprints allowed)
		)
		(placement
			(enabled no)
			(sheetname "")
		)
		(fill
			(thermal_gap 0.5)
			(thermal_bridge_width 0.5)
			(island_removal_mode 0)
		)
		(polygon
			(pts
				(xy 59.822842 -217.516456) (xy 59.822842 -217.072718) (xy 62.147958 -217.072718) (xy 62.147958 -217.516456)
			)
		)
	)
	(zone
		(layer "F.Cu")
		(hatch none 0.5)
		(connect_pads
			(clearance 0)
		)
		(min_thickness 0.25)
		(keepout
			(tracks allowed)
			(vias allowed)
			(pads allowed)
			(copperpour allowed)
			(footprints allowed)
		)
		(placement
			(enabled no)
			(sheetname "")
		)
		(fill
			(thermal_gap 0.5)
			(thermal_bridge_width 0.5)
			(island_removal_mode 0)
		)
		(polygon
			(pts
				(xy 180.423058 -233.555032) (xy 180.423058 -233.326432) (xy 182.455058 -233.326432) (xy 182.455058 -233.555032)
			)
		)
	)
	(zone
		(layer "F.Cu")
		(hatch none 0.5)
		(connect_pads
			(clearance 0)
		)
		(min_thickness 0.25)
		(keepout
			(tracks allowed)
			(vias allowed)
			(pads allowed)
			(copperpour allowed)
			(footprints allowed)
		)
		(placement
			(enabled no)
			(sheetname "")
		)
		(fill
			(thermal_gap 0.5)
			(thermal_bridge_width 0.5)
			(island_removal_mode 0)
		)
		(polygon
			(pts
				(xy 458.538326 -236.104938) (xy 458.538326 -235.876338) (xy 460.570326 -235.876338) (xy 460.570326 -236.104938)
			)
		)
	)
	(zone
		(layer "F.Cu")
		(hatch none 0.5)
		(connect_pads
			(clearance 0)
		)
		(min_thickness 0.25)
		(keepout
			(tracks allowed)
			(vias allowed)
			(pads allowed)
			(copperpour allowed)
			(footprints allowed)
		)
		(placement
			(enabled no)
			(sheetname "")
		)
		(fill
			(thermal_gap 0.5)
			(thermal_bridge_width 0.5)
			(island_removal_mode 0)
		)
		(polygon
			(pts
				(xy 195.510658 -286.254952) (xy 195.510658 -286.026352) (xy 197.542658 -286.026352) (xy 197.542658 -286.254952)
			)
		)
	)
	(zone
		(layer "F.Cu")
		(hatch none 0.5)
		(connect_pads
			(clearance 0)
		)
		(min_thickness 0.25)
		(keepout
			(tracks allowed)
			(vias allowed)
			(pads allowed)
			(copperpour allowed)
			(footprints allowed)
		)
		(placement
			(enabled no)
			(sheetname "")
		)
		(fill
			(thermal_gap 0.5)
			(thermal_bridge_width 0.5)
			(island_removal_mode 0)
		)
		(polygon
			(pts
				(xy 413.275526 -217.40495) (xy 413.275526 -217.17635) (xy 415.307526 -217.17635) (xy 415.307526 -217.40495)
			)
		)
	)
	(zone
		(layer "F.Cu")
		(hatch none 0.5)
		(connect_pads
			(clearance 0)
		)
		(min_thickness 0.25)
		(keepout
			(tracks not_allowed)
			(vias allowed)
			(pads allowed)
			(copperpour not_allowed)
			(footprints allowed)
		)
		(placement
			(enabled no)
			(sheetname "")
		)
		(fill
			(thermal_gap 0.5)
			(thermal_bridge_width 0.5)
			(island_removal_mode 0)
		)
		(polygon
			(pts
				(xy 78.632304 -344.543888) (xy 78.87462 -344.543888) (xy 78.87462 -343.578688) (xy 78.632304 -343.578688)
			)
		)
	)
	(zone
		(layer "F.Cu")
		(hatch none 0.5)
		(connect_pads
			(clearance 0)
		)
		(min_thickness 0.25)
		(keepout
			(tracks allowed)
			(vias allowed)
			(pads allowed)
			(copperpour allowed)
			(footprints allowed)
		)
		(placement
			(enabled no)
			(sheetname "")
		)
		(fill
			(thermal_gap 0.5)
			(thermal_bridge_width 0.5)
			(island_removal_mode 0)
		)
		(polygon
			(pts
				(xy 311.91708 -233.2228) (xy 314.15228 -233.2228) (xy 314.26023 -233.2228) (xy 314.26023 -234.173776)
				(xy 311.715404 -234.173776) (xy 311.715404 -233.2228)
			)
		)
	)
	(zone
		(layer "F.Cu")
		(hatch none 0.5)
		(connect_pads
			(clearance 0)
		)
		(min_thickness 0.25)
		(keepout
			(tracks allowed)
			(vias allowed)
			(pads allowed)
			(copperpour allowed)
			(footprints allowed)
		)
		(placement
			(enabled no)
			(sheetname "")
		)
		(fill
			(thermal_gap 0.5)
			(thermal_bridge_width 0.5)
			(island_removal_mode 0)
		)
		(polygon
			(pts
				(xy 29.647642 -231.116632) (xy 29.647642 -230.672894) (xy 31.972758 -230.672894) (xy 31.972758 -231.116632)
			)
		)
	)
	(zone
		(layer "F.Cu")
		(hatch none 0.5)
		(connect_pads
			(clearance 0)
		)
		(min_thickness 0.25)
		(keepout
			(tracks allowed)
			(vias allowed)
			(pads allowed)
			(copperpour allowed)
			(footprints allowed)
		)
		(placement
			(enabled no)
			(sheetname "")
		)
		(fill
			(thermal_gap 0.5)
			(thermal_bridge_width 0.5)
			(island_removal_mode 0)
		)
		(polygon
			(pts
				(xy 138.24712 -217.655648) (xy 138.53414 -217.655648) (xy 138.56462 -217.625168) (xy 138.56462 -216.997788)
				(xy 138.47826 -216.911428) (xy 138.2903 -216.911428) (xy 138.21664 -216.985088) (xy 138.21664 -217.625168)
			)
		)
	)
	(zone
		(layer "F.Cu")
		(hatch none 0.5)
		(connect_pads
			(clearance 0)
		)
		(min_thickness 0.25)
		(keepout
			(tracks allowed)
			(vias allowed)
			(pads allowed)
			(copperpour allowed)
			(footprints allowed)
		)
		(placement
			(enabled no)
			(sheetname "")
		)
		(fill
			(thermal_gap 0.5)
			(thermal_bridge_width 0.5)
			(island_removal_mode 0)
		)
		(polygon
			(pts
				(xy 78.155292 -404.802594) (xy 78.155292 -399.959576) (xy 80.039718 -399.959576) (xy 80.039718 -404.802594)
			)
		)
	)
	(zone
		(layer "F.Cu")
		(hatch none 0.5)
		(connect_pads
			(clearance 0)
		)
		(min_thickness 0.25)
		(keepout
			(tracks allowed)
			(vias allowed)
			(pads allowed)
			(copperpour allowed)
			(footprints allowed)
		)
		(placement
			(enabled no)
			(sheetname "")
		)
		(fill
			(thermal_gap 0.5)
			(thermal_bridge_width 0.5)
			(island_removal_mode 0)
		)
		(polygon
			(pts
				(xy 259.056378 -219.216478) (xy 259.056378 -218.77274) (xy 261.381494 -218.77274) (xy 261.381494 -219.216478)
			)
		)
	)
	(zone
		(layer "F.Cu")
		(hatch none 0.5)
		(connect_pads
			(clearance 0)
		)
		(min_thickness 0.25)
		(keepout
			(tracks allowed)
			(vias allowed)
			(pads allowed)
			(copperpour allowed)
			(footprints allowed)
		)
		(placement
			(enabled no)
			(sheetname "")
		)
		(fill
			(thermal_gap 0.5)
			(thermal_bridge_width 0.5)
			(island_removal_mode 0)
		)
		(polygon
			(pts
				(xy 325.94296 -335.435448) (xy 325.94296 -336.707988) (xy 326.3392 -337.104228) (xy 330.82738 -337.104228)
				(xy 331.1398 -336.791808) (xy 331.1398 -335.333848) (xy 330.84516 -335.039208) (xy 326.3392 -335.039208)
			)
		)
	)
	(zone
		(layer "F.Cu")
		(hatch none 0.5)
		(connect_pads
			(clearance 0)
		)
		(min_thickness 0.25)
		(keepout
			(tracks allowed)
			(vias allowed)
			(pads allowed)
			(copperpour allowed)
			(footprints allowed)
		)
		(placement
			(enabled no)
			(sheetname "")
		)
		(fill
			(thermal_gap 0.5)
			(thermal_bridge_width 0.5)
			(island_removal_mode 0)
		)
		(polygon
			(pts
				(xy 262.50011 -265.966448) (xy 262.50011 -265.52271) (xy 264.825226 -265.52271) (xy 264.825226 -265.966448)
			)
		)
	)
	(zone
		(layer "F.Cu")
		(hatch none 0.5)
		(connect_pads
			(clearance 0)
		)
		(min_thickness 0.25)
		(keepout
			(tracks allowed)
			(vias allowed)
			(pads allowed)
			(copperpour allowed)
			(footprints allowed)
		)
		(placement
			(enabled no)
			(sheetname "")
		)
		(fill
			(thermal_gap 0.5)
			(thermal_bridge_width 0.5)
			(island_removal_mode 0)
		)
		(polygon
			(pts
				(xy 14.560042 -271.066514) (xy 14.560042 -270.622776) (xy 16.885158 -270.622776) (xy 16.885158 -271.066514)
			)
		)
	)
	(zone
		(layer "F.Cu")
		(hatch none 0.5)
		(connect_pads
			(clearance 0)
		)
		(min_thickness 0.25)
		(keepout
			(tracks not_allowed)
			(vias allowed)
			(pads allowed)
			(copperpour not_allowed)
			(footprints allowed)
		)
		(placement
			(enabled no)
			(sheetname "")
		)
		(fill
			(thermal_gap 0.5)
			(thermal_bridge_width 0.5)
			(island_removal_mode 0)
		)
		(polygon
			(pts
				(xy 39.520622 -355.161088) (xy 39.762938 -355.161088) (xy 39.762938 -354.348288) (xy 39.520622 -354.348288)
			)
		)
	)
	(zone
		(layer "F.Cu")
		(hatch none 0.5)
		(connect_pads
			(clearance 0)
		)
		(min_thickness 0.25)
		(keepout
			(tracks allowed)
			(vias allowed)
			(pads allowed)
			(copperpour allowed)
			(footprints allowed)
		)
		(placement
			(enabled no)
			(sheetname "")
		)
		(fill
			(thermal_gap 0.5)
			(thermal_bridge_width 0.5)
			(island_removal_mode 0)
		)
		(polygon
			(pts
				(xy 262.50011 -280.416508) (xy 262.50011 -279.97277) (xy 264.825226 -279.97277) (xy 264.825226 -280.416508)
			)
		)
	)
	(zone
		(layer "F.Cu")
		(hatch none 0.5)
		(connect_pads
			(clearance 0)
		)
		(min_thickness 0.25)
		(keepout
			(tracks allowed)
			(vias allowed)
			(pads allowed)
			(copperpour allowed)
			(footprints allowed)
		)
		(placement
			(enabled no)
			(sheetname "")
		)
		(fill
			(thermal_gap 0.5)
			(thermal_bridge_width 0.5)
			(island_removal_mode 0)
		)
		(polygon
			(pts
				(xy 411.884368 -18.55978) (xy 411.884368 -15.425166) (xy 413.66313 -15.425166) (xy 413.66313 -18.55978)
			)
		)
	)
	(zone
		(layer "F.Cu")
		(hatch none 0.5)
		(connect_pads
			(clearance 0)
		)
		(min_thickness 0.25)
		(keepout
			(tracks allowed)
			(vias allowed)
			(pads allowed)
			(copperpour allowed)
			(footprints allowed)
		)
		(placement
			(enabled no)
			(sheetname "")
		)
		(fill
			(thermal_gap 0.5)
			(thermal_bridge_width 0.5)
			(island_removal_mode 0)
		)
		(polygon
			(pts
				(xy 147.358608 -229.09657) (xy 141.296644 -235.158788) (xy 141.296136 -235.158788) (xy 141.296136 -235.194348)
				(xy 141.232636 -235.257848) (xy 141.232636 -236.441996) (xy 141.262354 -236.471714) (xy 141.262354 -237.090458)
				(xy 141.2367 -237.116112) (xy 141.030452 -237.116112) (xy 140.845794 -237.116112) (xy 140.807694 -237.154212)
				(xy 140.807694 -237.559596) (xy 140.918184 -237.670086) (xy 141.015974 -237.670086) (xy 141.038072 -237.692184)
				(xy 141.038072 -238.49584) (xy 141.044676 -238.502444) (xy 141.28242 -238.502444) (xy 141.377416 -238.59744)
				(xy 141.377416 -238.87557) (xy 142.863062 -238.87557) (xy 149.285198 -232.453434) (xy 149.488906 -232.453434)
				(xy 150.066248 -231.876092) (xy 150.963884 -231.876092) (xy 151.190198 -231.876092) (xy 151.21763 -231.84866)
				(xy 151.21763 -230.521002) (xy 151.21763 -230.471472) (xy 151.301958 -230.387144) (xy 151.301958 -229.287324)
				(xy 151.21763 -229.202996) (xy 150.111206 -228.096572) (xy 150.111206 -227.435664) (xy 150.111206 -227.32746)
				(xy 149.524974 -226.741228) (xy 149.524974 -226.188524) (xy 149.524974 -226.085908) (xy 148.081238 -224.642172)
				(xy 148.29663 -224.427034) (xy 147.99183 -224.122234) (xy 147.99183 -223.334834) (xy 147.99183 -223.252284)
				(xy 147.36191 -223.252284) (xy 147.358608 -223.255332) (xy 147.358608 -223.334834)
			)
		)
	)
	(zone
		(layer "F.Cu")
		(hatch none 0.5)
		(connect_pads
			(clearance 0)
		)
		(min_thickness 0.25)
		(keepout
			(tracks allowed)
			(vias allowed)
			(pads allowed)
			(copperpour allowed)
			(footprints allowed)
		)
		(placement
			(enabled no)
			(sheetname "")
		)
		(fill
			(thermal_gap 0.5)
			(thermal_bridge_width 0.5)
			(island_removal_mode 0)
		)
		(polygon
			(pts
				(xy 137.8585 -283.299408) (xy 138.14552 -283.299408) (xy 138.176 -283.268928) (xy 138.176 -282.641548)
				(xy 138.08964 -282.555188) (xy 137.90168 -282.555188) (xy 137.82802 -282.628848) (xy 137.82802 -283.268928)
			)
		)
	)
	(zone
		(layer "F.Cu")
		(hatch none 0.5)
		(connect_pads
			(clearance 0)
		)
		(min_thickness 0.25)
		(keepout
			(tracks allowed)
			(vias allowed)
			(pads allowed)
			(copperpour allowed)
			(footprints allowed)
		)
		(placement
			(enabled no)
			(sheetname "")
		)
		(fill
			(thermal_gap 0.5)
			(thermal_bridge_width 0.5)
			(island_removal_mode 0)
		)
		(polygon
			(pts
				(xy 175.82134 -28.047188) (xy 179.8066 -28.047188) (xy 179.8066 -29.794708) (xy 175.82134 -29.794708)
			)
		)
	)
	(zone
		(layer "F.Cu")
		(hatch none 0.5)
		(connect_pads
			(clearance 0)
		)
		(min_thickness 0.25)
		(keepout
			(tracks not_allowed)
			(vias allowed)
			(pads allowed)
			(copperpour not_allowed)
			(footprints allowed)
		)
		(placement
			(enabled no)
			(sheetname "")
		)
		(fill
			(thermal_gap 0.5)
			(thermal_bridge_width 0.5)
			(island_removal_mode 0)
		)
		(polygon
			(pts
				(arc
					(start 5.340096 -347.699838)
					(mid 10.340086 -342.699848)
					(end 15.340076 -347.699838)
				)
				(arc
					(start 15.340076 -347.699838)
					(mid 10.340086 -352.699828)
					(end 5.340096 -347.699838)
				)
			)
		)
	)
	(zone
		(layer "F.Cu")
		(hatch none 0.5)
		(connect_pads
			(clearance 0)
		)
		(min_thickness 0.25)
		(keepout
			(tracks allowed)
			(vias allowed)
			(pads allowed)
			(copperpour allowed)
			(footprints allowed)
		)
		(placement
			(enabled no)
			(sheetname "")
		)
		(fill
			(thermal_gap 0.5)
			(thermal_bridge_width 0.5)
			(island_removal_mode 0)
		)
		(polygon
			(pts
				(xy 386.347716 -278.637492) (xy 386.550662 -278.840438) (xy 386.593588 -278.840438) (xy 387.037326 -278.396954)
				(xy 387.037326 -278.27478) (xy 386.904484 -278.141684) (xy 386.800344 -278.141684) (xy 386.347716 -278.594312)
			)
		)
	)
	(zone
		(layer "F.Cu")
		(hatch none 0.5)
		(connect_pads
			(clearance 0)
		)
		(min_thickness 0.25)
		(keepout
			(tracks allowed)
			(vias allowed)
			(pads allowed)
			(copperpour allowed)
			(footprints allowed)
		)
		(placement
			(enabled no)
			(sheetname "")
		)
		(fill
			(thermal_gap 0.5)
			(thermal_bridge_width 0.5)
			(island_removal_mode 0)
		)
		(polygon
			(pts
				(xy 91.98102 -94.234508) (xy 91.98102 -92.885768) (xy 93.6117 -92.885768) (xy 93.6117 -94.234508)
			)
		)
	)
	(zone
		(layer "F.Cu")
		(hatch none 0.5)
		(connect_pads
			(clearance 0)
		)
		(min_thickness 0.25)
		(keepout
			(tracks allowed)
			(vias allowed)
			(pads allowed)
			(copperpour allowed)
			(footprints allowed)
		)
		(placement
			(enabled no)
			(sheetname "")
		)
		(fill
			(thermal_gap 0.5)
			(thermal_bridge_width 0.5)
			(island_removal_mode 0)
		)
		(polygon
			(pts
				(xy 292.67531 -315.266578) (xy 292.67531 -314.82284) (xy 295.000426 -314.82284) (xy 295.000426 -315.266578)
			)
		)
	)
	(zone
		(layer "F.Cu")
		(hatch none 0.5)
		(connect_pads
			(clearance 0)
		)
		(min_thickness 0.25)
		(keepout
			(tracks allowed)
			(vias allowed)
			(pads allowed)
			(copperpour allowed)
			(footprints allowed)
		)
		(placement
			(enabled no)
			(sheetname "")
		)
		(fill
			(thermal_gap 0.5)
			(thermal_bridge_width 0.5)
			(island_removal_mode 0)
		)
		(polygon
			(pts
				(xy 62.147958 -241.31651) (xy 59.822842 -241.31651) (xy 59.692794 -241.31651) (xy 59.692794 -240.394744)
				(xy 62.21349 -240.394744) (xy 62.21349 -241.31651)
			)
		)
	)
	(zone
		(layer "F.Cu")
		(hatch none 0.5)
		(connect_pads
			(clearance 0)
		)
		(min_thickness 0.25)
		(keepout
			(tracks allowed)
			(vias allowed)
			(pads allowed)
			(copperpour allowed)
			(footprints not_allowed)
		)
		(placement
			(enabled no)
			(sheetname "")
		)
		(fill
			(thermal_gap 0.5)
			(thermal_bridge_width 0.5)
			(island_removal_mode 0)
		)
		(polygon
			(pts
				(xy 255.080008 -185.092086) (xy 313.986926 -185.092086) (xy 313.986926 -177.092102) (xy 255.080008 -177.092102)
			)
		)
	)
	(zone
		(layer "F.Cu")
		(hatch none 0.5)
		(connect_pads
			(clearance 0)
		)
		(min_thickness 0.25)
		(keepout
			(tracks allowed)
			(vias allowed)
			(pads allowed)
			(copperpour allowed)
			(footprints allowed)
		)
		(placement
			(enabled no)
			(sheetname "")
		)
		(fill
			(thermal_gap 0.5)
			(thermal_bridge_width 0.5)
			(island_removal_mode 0)
		)
		(polygon
			(pts
				(xy 31.972758 -233.666538) (xy 29.647642 -233.666538) (xy 29.516578 -233.666538) (xy 29.516578 -232.683558)
				(xy 32.037274 -232.683558) (xy 32.037274 -233.666538)
			)
		)
	)
	(zone
		(layer "F.Cu")
		(hatch none 0.5)
		(connect_pads
			(clearance 0)
		)
		(min_thickness 0.25)
		(keepout
			(tracks allowed)
			(vias allowed)
			(pads allowed)
			(copperpour allowed)
			(footprints allowed)
		)
		(placement
			(enabled no)
			(sheetname "")
		)
		(fill
			(thermal_gap 0.5)
			(thermal_bridge_width 0.5)
			(island_removal_mode 0)
		)
		(polygon
			(pts
				(xy 157.791658 -277.526496) (xy 159.823658 -277.526496) (xy 159.823658 -277.528782) (xy 160.002474 -277.528782)
				(xy 160.002474 -277.766018) (xy 160.140396 -277.766018) (xy 160.183576 -277.809198) (xy 160.183576 -277.94204)
				(xy 160.183576 -278.246078) (xy 160.110932 -278.318722) (xy 157.570678 -278.318722) (xy 157.429454 -278.177498)
				(xy 157.429454 -277.980394) (xy 157.510988 -277.89886) (xy 157.510988 -277.526496) (xy 157.608524 -277.526496)
				(xy 157.655514 -277.526496)
			)
		)
	)
	(zone
		(layer "F.Cu")
		(hatch none 0.5)
		(connect_pads
			(clearance 0)
		)
		(min_thickness 0.25)
		(keepout
			(tracks allowed)
			(vias allowed)
			(pads allowed)
			(copperpour allowed)
			(footprints not_allowed)
		)
		(placement
			(enabled no)
			(sheetname "")
		)
		(fill
			(thermal_gap 0.5)
			(thermal_bridge_width 0.5)
			(island_removal_mode 0)
		)
		(polygon
			(pts
				(xy 34.56432 -79.774288)
				(arc
					(start 2.566162 -79.774288)
					(mid 2.889515 -80.521689)
					(end 2.999994 -81.328514)
				)
				(xy 2.999994 -82.77098) (xy 34.562288 -82.774282)
			)
		)
	)
	(zone
		(layer "F.Cu")
		(hatch none 0.5)
		(connect_pads
			(clearance 0)
		)
		(min_thickness 0.25)
		(keepout
			(tracks allowed)
			(vias allowed)
			(pads allowed)
			(copperpour allowed)
			(footprints allowed)
		)
		(placement
			(enabled no)
			(sheetname "")
		)
		(fill
			(thermal_gap 0.5)
			(thermal_bridge_width 0.5)
			(island_removal_mode 0)
		)
		(polygon
			(pts
				(xy 159.834834 -274.35683) (xy 157.802834 -274.35683) (xy 157.802834 -274.354544) (xy 157.668976 -274.354544)
				(xy 157.668976 -273.564604) (xy 159.959294 -273.564604) (xy 159.959294 -274.35683)
			)
		)
	)
	(zone
		(layer "F.Cu")
		(hatch none 0.5)
		(connect_pads
			(clearance 0)
		)
		(min_thickness 0.25)
		(keepout
			(tracks allowed)
			(vias allowed)
			(pads allowed)
			(copperpour allowed)
			(footprints allowed)
		)
		(placement
			(enabled no)
			(sheetname "")
		)
		(fill
			(thermal_gap 0.5)
			(thermal_bridge_width 0.5)
			(island_removal_mode 0)
		)
		(polygon
			(pts
				(xy 332.177136 -242.356132) (xy 332.380082 -242.559078) (xy 332.423008 -242.559078) (xy 332.866746 -242.115594)
				(xy 332.866746 -241.99342) (xy 332.733904 -241.860324) (xy 332.629764 -241.860324) (xy 332.177136 -242.312952)
			)
		)
	)
	(zone
		(layer "F.Cu")
		(hatch none 0.5)
		(connect_pads
			(clearance 0)
		)
		(min_thickness 0.25)
		(keepout
			(tracks allowed)
			(vias allowed)
			(pads allowed)
			(copperpour allowed)
			(footprints allowed)
		)
		(placement
			(enabled no)
			(sheetname "")
		)
		(fill
			(thermal_gap 0.5)
			(thermal_bridge_width 0.5)
			(island_removal_mode 0)
		)
		(polygon
			(pts
				(xy 176.979326 -206.976472) (xy 179.011326 -206.976472) (xy 179.011326 -207.205072) (xy 176.979326 -207.205072)
				(xy 176.843182 -207.205072) (xy 176.796192 -207.205072) (xy 176.796192 -206.976472) (xy 176.843182 -206.976472)
			)
		)
	)
	(zone
		(layer "F.Cu")
		(hatch none 0.5)
		(connect_pads
			(clearance 0)
		)
		(min_thickness 0.25)
		(keepout
			(tracks allowed)
			(vias allowed)
			(pads allowed)
			(copperpour allowed)
			(footprints not_allowed)
		)
		(placement
			(enabled no)
			(sheetname "")
		)
		(fill
			(thermal_gap 0.5)
			(thermal_bridge_width 0.5)
			(island_removal_mode 0)
		)
		(polygon
			(pts
				(xy 7.13994 -185.092086) (xy 66.047112 -185.092086) (xy 66.047112 -177.092102) (xy 7.13994 -177.092102)
			)
		)
	)
	(zone
		(layer "F.Cu")
		(hatch none 0.5)
		(connect_pads
			(clearance 0)
		)
		(min_thickness 0.25)
		(keepout
			(tracks allowed)
			(vias allowed)
			(pads allowed)
			(copperpour allowed)
			(footprints allowed)
		)
		(placement
			(enabled no)
			(sheetname "")
		)
		(fill
			(thermal_gap 0.5)
			(thermal_bridge_width 0.5)
			(island_removal_mode 0)
		)
		(polygon
			(pts
				(xy 273.68627 -269.874238) (xy 276.879812 -269.874238) (xy 276.979634 -269.774416) (xy 276.979634 -268.789912)
				(xy 276.77999 -268.590268) (xy 273.440144 -268.590268) (xy 273.233896 -268.796516) (xy 273.233896 -269.421864)
			)
		)
	)
	(zone
		(layer "F.Cu")
		(hatch none 0.5)
		(connect_pads
			(clearance 0)
		)
		(min_thickness 0.25)
		(keepout
			(tracks allowed)
			(vias allowed)
			(pads allowed)
			(copperpour allowed)
			(footprints allowed)
		)
		(placement
			(enabled no)
			(sheetname "")
		)
		(fill
			(thermal_gap 0.5)
			(thermal_bridge_width 0.5)
			(island_removal_mode 0)
		)
		(polygon
			(pts
				(xy 26.20391 -294.866568) (xy 26.20391 -294.42283) (xy 28.529026 -294.42283) (xy 28.529026 -294.866568)
			)
		)
	)
	(zone
		(layer "F.Cu")
		(hatch none 0.5)
		(connect_pads
			(clearance 0)
		)
		(min_thickness 0.25)
		(keepout
			(tracks not_allowed)
			(vias allowed)
			(pads allowed)
			(copperpour not_allowed)
			(footprints allowed)
		)
		(placement
			(enabled no)
			(sheetname "")
		)
		(fill
			(thermal_gap 0.5)
			(thermal_bridge_width 0.5)
			(island_removal_mode 0)
		)
		(polygon
			(pts
				(xy 297.49496 -413.83966) (xy 297.49496 -411.76194) (xy 297.29684 -411.76194) (xy 297.29684 -413.83966)
			)
		)
	)
	(zone
		(layer "F.Cu")
		(hatch none 0.5)
		(connect_pads
			(clearance 0)
		)
		(min_thickness 0.25)
		(keepout
			(tracks allowed)
			(vias allowed)
			(pads allowed)
			(copperpour allowed)
			(footprints allowed)
		)
		(placement
			(enabled no)
			(sheetname "")
		)
		(fill
			(thermal_gap 0.5)
			(thermal_bridge_width 0.5)
			(island_removal_mode 0)
		)
		(polygon
			(pts
				(xy 50.368708 -352.740214) (xy 48.552608 -352.740214) (xy 48.552608 -351.360994) (xy 50.368708 -351.360994)
			)
		)
	)
	(zone
		(layer "F.Cu")
		(hatch none 0.5)
		(connect_pads
			(clearance 0)
		)
		(min_thickness 0.25)
		(keepout
			(tracks allowed)
			(vias allowed)
			(pads allowed)
			(copperpour allowed)
			(footprints allowed)
		)
		(placement
			(enabled no)
			(sheetname "")
		)
		(fill
			(thermal_gap 0.5)
			(thermal_bridge_width 0.5)
			(island_removal_mode 0)
		)
		(polygon
			(pts
				(xy 209.12836 -404.35022) (xy 209.12836 -401.01774) (xy 212.5091 -401.01774) (xy 212.5091 -404.35022)
			)
		)
	)
	(zone
		(layer "F.Cu")
		(hatch none 0.5)
		(connect_pads
			(clearance 0)
		)
		(min_thickness 0.25)
		(keepout
			(tracks allowed)
			(vias allowed)
			(pads allowed)
			(copperpour allowed)
			(footprints allowed)
		)
		(placement
			(enabled no)
			(sheetname "")
		)
		(fill
			(thermal_gap 0.5)
			(thermal_bridge_width 0.5)
			(island_removal_mode 0)
		)
		(polygon
			(pts
				(xy 387.275324 -236.844332) (xy 387.47827 -236.641386) (xy 387.47827 -236.59846) (xy 387.034786 -236.154722)
				(xy 386.912612 -236.154722) (xy 386.779516 -236.287564) (xy 386.779516 -236.391704) (xy 387.232144 -236.844332)
			)
		)
	)
	(zone
		(layer "F.Cu")
		(hatch none 0.5)
		(connect_pads
			(clearance 0)
		)
		(min_thickness 0.25)
		(keepout
			(tracks allowed)
			(vias allowed)
			(pads allowed)
			(copperpour allowed)
			(footprints not_allowed)
		)
		(placement
			(enabled no)
			(sheetname "")
		)
		(fill
			(thermal_gap 0.5)
			(thermal_bridge_width 0.5)
			(island_removal_mode 0)
		)
		(polygon
			(pts
				(xy 19.454114 -161.26333) (xy 40.454072 -161.265616) (xy 40.456358 -139.26566) (xy 19.4564 -139.284964)
			)
		)
	)
	(zone
		(layer "F.Cu")
		(hatch none 0.5)
		(connect_pads
			(clearance 0)
		)
		(min_thickness 0.25)
		(keepout
			(tracks not_allowed)
			(vias allowed)
			(pads allowed)
			(copperpour not_allowed)
			(footprints allowed)
		)
		(placement
			(enabled no)
			(sheetname "")
		)
		(fill
			(thermal_gap 0.5)
			(thermal_bridge_width 0.5)
			(island_removal_mode 0)
		)
		(polygon
			(pts
				(xy 214.215218 -55.499762) (xy 216.304114 -55.499762) (xy 216.304114 -54.374288) (xy 216.161366 -54.374288)
				(xy 216.161366 -55.357014) (xy 214.357966 -55.357014) (xy 214.357966 -54.480714) (xy 214.215218 -54.480714)
			)
		)
	)
	(zone
		(layer "F.Cu")
		(hatch none 0.5)
		(connect_pads
			(clearance 0)
		)
		(min_thickness 0.25)
		(keepout
			(tracks allowed)
			(vias allowed)
			(pads allowed)
			(copperpour allowed)
			(footprints not_allowed)
		)
		(placement
			(enabled no)
			(sheetname "")
		)
		(fill
			(thermal_gap 0.5)
			(thermal_bridge_width 0.5)
			(island_removal_mode 0)
		)
		(polygon
			(pts
				(xy 12.58697 -12.850114) (xy 82.226912 -12.850114)
				(arc
					(start 82.226912 -12.392406)
					(mid 81.11103 -11.292493)
					(end 80.701896 -9.780016)
				)
				(xy 80.701896 -0.999998) (xy 14.10208 -0.999998)
				(arc
					(start 14.10208 -9.780016)
					(mid 13.695719 -11.28742)
					(end 12.58697 -12.386564)
				)
			)
		)
	)
	(zone
		(layer "F.Cu")
		(hatch none 0.5)
		(connect_pads
			(clearance 0)
		)
		(min_thickness 0.25)
		(keepout
			(tracks allowed)
			(vias allowed)
			(pads allowed)
			(copperpour allowed)
			(footprints allowed)
		)
		(placement
			(enabled no)
			(sheetname "")
		)
		(fill
			(thermal_gap 0.5)
			(thermal_bridge_width 0.5)
			(island_removal_mode 0)
		)
		(polygon
			(pts
				(xy 359.44048 -56.38038) (xy 359.44048 -55.40502) (xy 362.2167 -55.40502) (xy 362.2167 -56.38038)
			)
		)
	)
	(zone
		(layer "F.Cu")
		(hatch none 0.5)
		(connect_pads
			(clearance 0)
		)
		(min_thickness 0.25)
		(keepout
			(tracks allowed)
			(vias allowed)
			(pads allowed)
			(copperpour allowed)
			(footprints not_allowed)
		)
		(placement
			(enabled no)
			(sheetname "")
		)
		(fill
			(thermal_gap 0.5)
			(thermal_bridge_width 0.5)
			(island_removal_mode 0)
		)
		(polygon
			(pts
				(xy 449.279518 -374.753886) (xy 467.300056 -374.753886) (xy 467.300056 -350.763586)
				(arc
					(start 465.411566 -350.763586)
					(mid 461.46001 -352.700009)
					(end 457.508356 -350.763586)
				)
				(xy 449.279518 -350.763586)
			)
		)
	)
	(zone
		(layer "F.Cu")
		(hatch none 0.5)
		(connect_pads
			(clearance 0)
		)
		(min_thickness 0.25)
		(keepout
			(tracks not_allowed)
			(vias allowed)
			(pads allowed)
			(copperpour not_allowed)
			(footprints allowed)
		)
		(placement
			(enabled no)
			(sheetname "")
		)
		(fill
			(thermal_gap 0.5)
			(thermal_bridge_width 0.5)
			(island_removal_mode 0)
		)
		(polygon
			(pts
				(xy 375.53519 -338.785708) (xy 375.777506 -338.785708) (xy 375.777506 -337.757008) (xy 375.53519 -337.757008)
			)
		)
	)
	(zone
		(layer "F.Cu")
		(hatch none 0.5)
		(connect_pads
			(clearance 0)
		)
		(min_thickness 0.25)
		(keepout
			(tracks allowed)
			(vias allowed)
			(pads allowed)
			(copperpour allowed)
			(footprints allowed)
		)
		(placement
			(enabled no)
			(sheetname "")
		)
		(fill
			(thermal_gap 0.5)
			(thermal_bridge_width 0.5)
			(island_removal_mode 0)
		)
		(polygon
			(pts
				(xy 207.154526 -245.454932) (xy 207.154526 -245.226332) (xy 209.186526 -245.226332) (xy 209.186526 -245.454932)
			)
		)
	)
	(zone
		(layer "F.Cu")
		(hatch none 0.5)
		(connect_pads
			(clearance 0)
		)
		(min_thickness 0.25)
		(keepout
			(tracks allowed)
			(vias allowed)
			(pads allowed)
			(copperpour allowed)
			(footprints allowed)
		)
		(placement
			(enabled no)
			(sheetname "")
		)
		(fill
			(thermal_gap 0.5)
			(thermal_bridge_width 0.5)
			(island_removal_mode 0)
		)
		(polygon
			(pts
				(xy 409.878022 -268.404848) (xy 409.878022 -268.176248) (xy 411.808422 -268.176248) (xy 411.808422 -268.404848)
			)
		)
	)
	(zone
		(layer "F.Cu")
		(hatch none 0.5)
		(connect_pads
			(clearance 0)
		)
		(min_thickness 0.25)
		(keepout
			(tracks allowed)
			(vias allowed)
			(pads allowed)
			(copperpour allowed)
			(footprints allowed)
		)
		(placement
			(enabled no)
			(sheetname "")
		)
		(fill
			(thermal_gap 0.5)
			(thermal_bridge_width 0.5)
			(island_removal_mode 0)
		)
		(polygon
			(pts
				(xy 15.00378 -18.30324) (xy 15.00378 -17.52092) (xy 14.20876 -17.52092) (xy 14.20876 -18.30324)
			)
		)
	)
	(zone
		(layer "F.Cu")
		(hatch none 0.5)
		(connect_pads
			(clearance 0)
		)
		(min_thickness 0.25)
		(keepout
			(tracks allowed)
			(vias allowed)
			(pads allowed)
			(copperpour allowed)
			(footprints allowed)
		)
		(placement
			(enabled no)
			(sheetname "")
		)
		(fill
			(thermal_gap 0.5)
			(thermal_bridge_width 0.5)
			(island_removal_mode 0)
		)
		(polygon
			(pts
				(xy 180.0098 -51.407568) (xy 180.0098 -49.639728) (xy 182.89524 -49.639728) (xy 182.89524 -51.407568)
			)
		)
	)
	(zone
		(layer "F.Cu")
		(hatch none 0.5)
		(connect_pads
			(clearance 0)
		)
		(min_thickness 0.25)
		(keepout
			(tracks allowed)
			(vias allowed)
			(pads allowed)
			(copperpour allowed)
			(footprints allowed)
		)
		(placement
			(enabled no)
			(sheetname "")
		)
		(fill
			(thermal_gap 0.5)
			(thermal_bridge_width 0.5)
			(island_removal_mode 0)
		)
		(polygon
			(pts
				(xy 304.319178 -308.46649) (xy 304.319178 -308.022752) (xy 306.644294 -308.022752) (xy 306.644294 -308.46649)
			)
		)
	)
	(zone
		(layer "F.Cu")
		(hatch none 0.5)
		(connect_pads
			(clearance 0)
		)
		(min_thickness 0.25)
		(keepout
			(tracks allowed)
			(vias allowed)
			(pads allowed)
			(copperpour allowed)
			(footprints allowed)
		)
		(placement
			(enabled no)
			(sheetname "")
		)
		(fill
			(thermal_gap 0.5)
			(thermal_bridge_width 0.5)
			(island_removal_mode 0)
		)
		(polygon
			(pts
				(xy 409.831794 -229.926388) (xy 411.863794 -229.926388) (xy 411.863794 -230.154988) (xy 409.831794 -230.154988)
				(xy 409.69565 -230.154988) (xy 409.64866 -230.154988) (xy 409.64866 -229.926388) (xy 409.69565 -229.926388)
			)
		)
	)
	(zone
		(layer "F.Cu")
		(hatch none 0.5)
		(connect_pads
			(clearance 0)
		)
		(min_thickness 0.25)
		(keepout
			(tracks allowed)
			(vias allowed)
			(pads allowed)
			(copperpour allowed)
			(footprints allowed)
		)
		(placement
			(enabled no)
			(sheetname "")
		)
		(fill
			(thermal_gap 0.5)
			(thermal_bridge_width 0.5)
			(island_removal_mode 0)
		)
		(polygon
			(pts
				(xy 165.335458 -207.204818) (xy 165.335458 -206.976218) (xy 167.367458 -206.976218) (xy 167.367458 -207.204818)
			)
		)
	)
	(zone
		(layer "F.Cu")
		(hatch none 0.5)
		(connect_pads
			(clearance 0)
		)
		(min_thickness 0.25)
		(keepout
			(tracks allowed)
			(vias allowed)
			(pads allowed)
			(copperpour allowed)
			(footprints allowed)
		)
		(placement
			(enabled no)
			(sheetname "")
		)
		(fill
			(thermal_gap 0.5)
			(thermal_bridge_width 0.5)
			(island_removal_mode 0)
		)
		(polygon
			(pts
				(xy 259.056378 -226.016566) (xy 259.056378 -225.572828) (xy 261.381494 -225.572828) (xy 261.381494 -226.016566)
			)
		)
	)
	(zone
		(layer "F.Cu")
		(hatch none 0.5)
		(connect_pads
			(clearance 0)
		)
		(min_thickness 0.25)
		(keepout
			(tracks allowed)
			(vias allowed)
			(pads allowed)
			(copperpour allowed)
			(footprints allowed)
		)
		(placement
			(enabled no)
			(sheetname "")
		)
		(fill
			(thermal_gap 0.5)
			(thermal_bridge_width 0.5)
			(island_removal_mode 0)
		)
		(polygon
			(pts
				(xy 440.006994 -219.726256) (xy 442.038994 -219.726256) (xy 442.038994 -219.954856) (xy 440.006994 -219.954856)
				(xy 439.875676 -219.954856) (xy 439.849768 -219.954856) (xy 439.849768 -219.726256) (xy 439.875676 -219.726256)
			)
		)
	)
	(zone
		(layer "F.Cu")
		(hatch none 0.5)
		(connect_pads
			(clearance 0)
		)
		(min_thickness 0.25)
		(keepout
			(tracks allowed)
			(vias allowed)
			(pads allowed)
			(copperpour allowed)
			(footprints allowed)
		)
		(placement
			(enabled no)
			(sheetname "")
		)
		(fill
			(thermal_gap 0.5)
			(thermal_bridge_width 0.5)
			(island_removal_mode 0)
		)
		(polygon
			(pts
				(xy 424.919394 -223.976438) (xy 426.951394 -223.976438) (xy 426.951394 -224.205038) (xy 424.919394 -224.205038)
				(xy 424.78325 -224.205038) (xy 424.73626 -224.205038) (xy 424.73626 -223.976438) (xy 424.78325 -223.976438)
			)
		)
	)
	(zone
		(layer "F.Cu")
		(hatch none 0.5)
		(connect_pads
			(clearance 0)
		)
		(min_thickness 0.25)
		(keepout
			(tracks allowed)
			(vias allowed)
			(pads allowed)
			(copperpour allowed)
			(footprints allowed)
		)
		(placement
			(enabled no)
			(sheetname "")
		)
		(fill
			(thermal_gap 0.5)
			(thermal_bridge_width 0.5)
			(island_removal_mode 0)
		)
		(polygon
			(pts
				(xy 274.143978 -196.266562) (xy 274.143978 -195.822824) (xy 276.469094 -195.822824) (xy 276.469094 -196.266562)
			)
		)
	)
	(zone
		(layer "F.Cu")
		(hatch none 0.5)
		(connect_pads
			(clearance 0)
		)
		(min_thickness 0.25)
		(keepout
			(tracks allowed)
			(vias allowed)
			(pads allowed)
			(copperpour allowed)
			(footprints allowed)
		)
		(placement
			(enabled no)
			(sheetname "")
		)
		(fill
			(thermal_gap 0.5)
			(thermal_bridge_width 0.5)
			(island_removal_mode 0)
		)
		(polygon
			(pts
				(xy 14.560042 -240.466626) (xy 14.560042 -240.022888) (xy 16.885158 -240.022888) (xy 16.885158 -240.466626)
			)
		)
	)
	(zone
		(layer "F.Cu")
		(hatch none 0.5)
		(connect_pads
			(clearance 0)
		)
		(min_thickness 0.25)
		(keepout
			(tracks allowed)
			(vias allowed)
			(pads allowed)
			(copperpour allowed)
			(footprints allowed)
		)
		(placement
			(enabled no)
			(sheetname "")
		)
		(fill
			(thermal_gap 0.5)
			(thermal_bridge_width 0.5)
			(island_removal_mode 0)
		)
		(polygon
			(pts
				(xy 139.175998 -275.05533) (xy 138.973052 -274.852384) (xy 138.929872 -274.852384) (xy 138.486134 -275.296122)
				(xy 138.486134 -275.418296) (xy 138.61923 -275.551138) (xy 138.72337 -275.551138) (xy 139.175998 -275.09851)
			)
		)
	)
	(zone
		(layer "F.Cu")
		(hatch none 0.5)
		(connect_pads
			(clearance 0)
		)
		(min_thickness 0.25)
		(keepout
			(tracks allowed)
			(vias allowed)
			(pads allowed)
			(copperpour allowed)
			(footprints allowed)
		)
		(placement
			(enabled no)
			(sheetname "")
		)
		(fill
			(thermal_gap 0.5)
			(thermal_bridge_width 0.5)
			(island_removal_mode 0)
		)
		(polygon
			(pts
				(xy 115.957096 -333.586582) (xy 112.421416 -333.586582) (xy 112.421416 -331.503782) (xy 115.957096 -331.503782)
			)
		)
	)
	(zone
		(layer "F.Cu")
		(hatch none 0.5)
		(connect_pads
			(clearance 0)
		)
		(min_thickness 0.25)
		(keepout
			(tracks allowed)
			(vias allowed)
			(pads allowed)
			(copperpour allowed)
			(footprints allowed)
		)
		(placement
			(enabled no)
			(sheetname "")
		)
		(fill
			(thermal_gap 0.5)
			(thermal_bridge_width 0.5)
			(island_removal_mode 0)
		)
		(polygon
			(pts
				(xy 44.735242 -292.316662) (xy 44.735242 -291.872924) (xy 47.060358 -291.872924) (xy 47.060358 -292.316662)
			)
		)
	)
	(zone
		(layer "F.Cu")
		(hatch none 0.5)
		(connect_pads
			(clearance 0)
		)
		(min_thickness 0.25)
		(keepout
			(tracks allowed)
			(vias allowed)
			(pads allowed)
			(copperpour allowed)
			(footprints allowed)
		)
		(placement
			(enabled no)
			(sheetname "")
		)
		(fill
			(thermal_gap 0.5)
			(thermal_bridge_width 0.5)
			(island_removal_mode 0)
		)
		(polygon
			(pts
				(xy 292.67531 -239.616488) (xy 292.67531 -239.17275) (xy 295.000426 -239.17275) (xy 295.000426 -239.616488)
			)
		)
	)
	(zone
		(layer "F.Cu")
		(hatch none 0.5)
		(connect_pads
			(clearance 0)
		)
		(min_thickness 0.25)
		(keepout
			(tracks allowed)
			(vias allowed)
			(pads allowed)
			(copperpour allowed)
			(footprints allowed)
		)
		(placement
			(enabled no)
			(sheetname "")
		)
		(fill
			(thermal_gap 0.5)
			(thermal_bridge_width 0.5)
			(island_removal_mode 0)
		)
		(polygon
			(pts
				(xy 311.84088 -219.216478) (xy 311.84088 -218.77274) (xy 314.17768 -218.77274) (xy 314.17768 -219.216478)
			)
		)
	)
	(zone
		(layer "F.Cu")
		(hatch none 0.5)
		(connect_pads
			(clearance 0)
		)
		(min_thickness 0.25)
		(keepout
			(tracks allowed)
			(vias allowed)
			(pads allowed)
			(copperpour allowed)
			(footprints allowed)
		)
		(placement
			(enabled no)
			(sheetname "")
		)
		(fill
			(thermal_gap 0.5)
			(thermal_bridge_width 0.5)
			(island_removal_mode 0)
		)
		(polygon
			(pts
				(xy 291.42436 -362.64596) (xy 287.88868 -362.64596) (xy 287.88868 -360.56316) (xy 291.42436 -360.56316)
			)
		)
	)
	(zone
		(layer "F.Cu")
		(hatch none 0.5)
		(connect_pads
			(clearance 0)
		)
		(min_thickness 0.25)
		(keepout
			(tracks allowed)
			(vias allowed)
			(pads allowed)
			(copperpour allowed)
			(footprints allowed)
		)
		(placement
			(enabled no)
			(sheetname "")
		)
		(fill
			(thermal_gap 0.5)
			(thermal_bridge_width 0.5)
			(island_removal_mode 0)
		)
		(polygon
			(pts
				(xy 59.822842 -263.416542) (xy 59.822842 -262.972804) (xy 62.147958 -262.972804) (xy 62.147958 -263.416542)
			)
		)
	)
	(zone
		(layer "F.Cu")
		(hatch none 0.5)
		(connect_pads
			(clearance 0)
		)
		(min_thickness 0.25)
		(keepout
			(tracks allowed)
			(vias allowed)
			(pads allowed)
			(copperpour allowed)
			(footprints allowed)
		)
		(placement
			(enabled no)
			(sheetname "")
		)
		(fill
			(thermal_gap 0.5)
			(thermal_bridge_width 0.5)
			(island_removal_mode 0)
		)
		(polygon
			(pts
				(xy 292.67531 -265.966448) (xy 292.67531 -265.52271) (xy 295.000426 -265.52271) (xy 295.000426 -265.966448)
			)
		)
	)
	(zone
		(layer "F.Cu")
		(hatch none 0.5)
		(connect_pads
			(clearance 0)
		)
		(min_thickness 0.25)
		(keepout
			(tracks allowed)
			(vias allowed)
			(pads allowed)
			(copperpour allowed)
			(footprints allowed)
		)
		(placement
			(enabled no)
			(sheetname "")
		)
		(fill
			(thermal_gap 0.5)
			(thermal_bridge_width 0.5)
			(island_removal_mode 0)
		)
		(polygon
			(pts
				(xy 455.094594 -229.926388) (xy 457.126594 -229.926388) (xy 457.126594 -230.154988) (xy 455.094594 -230.154988)
				(xy 454.95845 -230.154988) (xy 454.91146 -230.154988) (xy 454.91146 -229.926388) (xy 454.95845 -229.926388)
			)
		)
	)
	(zone
		(layer "F.Cu")
		(hatch none 0.5)
		(connect_pads
			(clearance 0)
		)
		(min_thickness 0.25)
		(keepout
			(tracks allowed)
			(vias allowed)
			(pads allowed)
			(copperpour allowed)
			(footprints not_allowed)
		)
		(placement
			(enabled no)
			(sheetname "")
		)
		(fill
			(thermal_gap 0.5)
			(thermal_bridge_width 0.5)
			(island_removal_mode 0)
		)
		(polygon
			(pts
				(xy 382.34874 -6.780022) (xy 382.34874 -14.780006) (xy 371.348762 -14.780006) (xy 371.348762 -6.780022)
			)
		)
	)
	(zone
		(layer "F.Cu")
		(hatch none 0.5)
		(connect_pads
			(clearance 0)
		)
		(min_thickness 0.25)
		(keepout
			(tracks not_allowed)
			(vias allowed)
			(pads allowed)
			(copperpour not_allowed)
			(footprints allowed)
		)
		(placement
			(enabled no)
			(sheetname "")
		)
		(fill
			(thermal_gap 0.5)
			(thermal_bridge_width 0.5)
			(island_removal_mode 0)
		)
		(polygon
			(pts
				(xy 359.214166 -336.26044) (xy 363.150912 -336.26044) (xy 362.966 -336.075528) (xy 361.60202 -336.075528)
				(xy 361.60202 -333.916528) (xy 363.758734 -333.916528) (xy 363.758734 -333.666846) (xy 361.44962 -333.666846)
				(xy 361.44962 -333.985108) (xy 361.310682 -333.985108) (xy 361.310682 -336.019902) (xy 359.456482 -336.019902)
				(xy 359.456482 -335.778856) (xy 359.214166 -335.778856)
			)
		)
	)
	(zone
		(layer "F.Cu")
		(hatch none 0.5)
		(connect_pads
			(clearance 0)
		)
		(min_thickness 0.25)
		(keepout
			(tracks allowed)
			(vias allowed)
			(pads allowed)
			(copperpour allowed)
			(footprints allowed)
		)
		(placement
			(enabled no)
			(sheetname "")
		)
		(fill
			(thermal_gap 0.5)
			(thermal_bridge_width 0.5)
			(island_removal_mode 0)
		)
		(polygon
			(pts
				(xy 279.912826 -271.066514) (xy 277.58771 -271.066514) (xy 277.456392 -271.066514) (xy 277.456392 -270.132556)
				(xy 279.96896 -270.132556) (xy 279.96896 -271.066514)
			)
		)
	)
	(zone
		(layer "F.Cu")
		(hatch none 0.5)
		(connect_pads
			(clearance 0)
		)
		(min_thickness 0.25)
		(keepout
			(tracks allowed)
			(vias allowed)
			(pads allowed)
			(copperpour allowed)
			(footprints allowed)
		)
		(placement
			(enabled no)
			(sheetname "")
		)
		(fill
			(thermal_gap 0.5)
			(thermal_bridge_width 0.5)
			(island_removal_mode 0)
		)
		(polygon
			(pts
				(xy 455.094594 -306.426362) (xy 457.126594 -306.426362) (xy 457.126594 -306.654962) (xy 455.094594 -306.654962)
				(xy 454.95845 -306.654962) (xy 454.91146 -306.654962) (xy 454.91146 -306.426362) (xy 454.95845 -306.426362)
			)
		)
	)
	(zone
		(layer "F.Cu")
		(hatch none 0.5)
		(connect_pads
			(clearance 0)
		)
		(min_thickness 0.25)
		(keepout
			(tracks allowed)
			(vias allowed)
			(pads allowed)
			(copperpour allowed)
			(footprints allowed)
		)
		(placement
			(enabled no)
			(sheetname "")
		)
		(fill
			(thermal_gap 0.5)
			(thermal_bridge_width 0.5)
			(island_removal_mode 0)
		)
		(polygon
			(pts
				(xy 59.822842 -230.266494) (xy 59.822842 -229.822756) (xy 62.147958 -229.822756) (xy 62.147958 -230.266494)
			)
		)
	)
	(zone
		(layer "F.Cu")
		(hatch none 0.5)
		(connect_pads
			(clearance 0)
		)
		(min_thickness 0.25)
		(keepout
			(tracks allowed)
			(vias allowed)
			(pads allowed)
			(copperpour allowed)
			(footprints allowed)
		)
		(placement
			(enabled no)
			(sheetname "")
		)
		(fill
			(thermal_gap 0.5)
			(thermal_bridge_width 0.5)
			(island_removal_mode 0)
		)
		(polygon
			(pts
				(xy 311.91708 -214.96655) (xy 311.91708 -214.522812) (xy 314.12688 -214.522812) (xy 314.12688 -214.96655)
			)
		)
	)
	(zone
		(layer "F.Cu")
		(hatch none 0.5)
		(connect_pads
			(clearance 0)
		)
		(min_thickness 0.25)
		(keepout
			(tracks allowed)
			(vias allowed)
			(pads allowed)
			(copperpour allowed)
			(footprints allowed)
		)
		(placement
			(enabled no)
			(sheetname "")
		)
		(fill
			(thermal_gap 0.5)
			(thermal_bridge_width 0.5)
			(island_removal_mode 0)
		)
		(polygon
			(pts
				(xy 333.66202 -284.076648) (xy 333.94904 -284.076648) (xy 333.97952 -284.046168) (xy 333.97952 -283.418788)
				(xy 333.89316 -283.332428) (xy 333.7052 -283.332428) (xy 333.63154 -283.406088) (xy 333.63154 -284.046168)
			)
		)
	)
	(zone
		(layer "F.Cu")
		(hatch none 0.5)
		(connect_pads
			(clearance 0)
		)
		(min_thickness 0.25)
		(keepout
			(tracks allowed)
			(vias allowed)
			(pads allowed)
			(copperpour allowed)
			(footprints allowed)
		)
		(placement
			(enabled no)
			(sheetname "")
		)
		(fill
			(thermal_gap 0.5)
			(thermal_bridge_width 0.5)
			(island_removal_mode 0)
		)
		(polygon
			(pts
				(xy 210.598258 -222.505016) (xy 210.598258 -222.276416) (xy 212.630258 -222.276416) (xy 212.630258 -222.505016)
			)
		)
	)
	(zone
		(layer "F.Cu")
		(hatch none 0.5)
		(connect_pads
			(clearance 0)
		)
		(min_thickness 0.25)
		(keepout
			(tracks allowed)
			(vias allowed)
			(pads allowed)
			(copperpour allowed)
			(footprints allowed)
		)
		(placement
			(enabled no)
			(sheetname "")
		)
		(fill
			(thermal_gap 0.5)
			(thermal_bridge_width 0.5)
			(island_removal_mode 0)
		)
		(polygon
			(pts
				(xy 26.204164 -229.416356) (xy 26.204164 -228.972618) (xy 28.52928 -228.972618) (xy 28.52928 -229.416356)
			)
		)
	)
	(zone
		(layer "F.Cu")
		(hatch none 0.5)
		(connect_pads
			(clearance 0)
		)
		(min_thickness 0.25)
		(keepout
			(tracks allowed)
			(vias allowed)
			(pads allowed)
			(copperpour allowed)
			(footprints allowed)
		)
		(placement
			(enabled no)
			(sheetname "")
		)
		(fill
			(thermal_gap 0.5)
			(thermal_bridge_width 0.5)
			(island_removal_mode 0)
		)
		(polygon
			(pts
				(xy 161.891726 -300.476412) (xy 163.923726 -300.476412) (xy 163.923726 -300.705012) (xy 161.891726 -300.705012)
				(xy 161.755582 -300.705012) (xy 161.708592 -300.705012) (xy 161.708592 -300.476412) (xy 161.755582 -300.476412)
			)
		)
	)
	(zone
		(layer "F.Cu")
		(hatch none 0.5)
		(connect_pads
			(clearance 0)
		)
		(min_thickness 0.25)
		(keepout
			(tracks allowed)
			(vias allowed)
			(pads allowed)
			(copperpour allowed)
			(footprints allowed)
		)
		(placement
			(enabled no)
			(sheetname "")
		)
		(fill
			(thermal_gap 0.5)
			(thermal_bridge_width 0.5)
			(island_removal_mode 0)
		)
		(polygon
			(pts
				(xy 277.58771 -311.866534) (xy 277.58771 -311.422796) (xy 279.912826 -311.422796) (xy 279.912826 -311.866534)
			)
		)
	)
	(zone
		(layer "F.Cu")
		(hatch none 0.5)
		(connect_pads
			(clearance 0)
		)
		(min_thickness 0.25)
		(keepout
			(tracks allowed)
			(vias allowed)
			(pads allowed)
			(copperpour allowed)
			(footprints allowed)
		)
		(placement
			(enabled no)
			(sheetname "")
		)
		(fill
			(thermal_gap 0.5)
			(thermal_bridge_width 0.5)
			(island_removal_mode 0)
		)
		(polygon
			(pts
				(xy 262.50011 -282.966414) (xy 262.50011 -282.522676) (xy 264.825226 -282.522676) (xy 264.825226 -282.966414)
			)
		)
	)
	(zone
		(layer "F.Cu")
		(hatch none 0.5)
		(connect_pads
			(clearance 0)
		)
		(min_thickness 0.25)
		(keepout
			(tracks allowed)
			(vias allowed)
			(pads allowed)
			(copperpour allowed)
			(footprints allowed)
		)
		(placement
			(enabled no)
			(sheetname "")
		)
		(fill
			(thermal_gap 0.5)
			(thermal_bridge_width 0.5)
			(island_removal_mode 0)
		)
		(polygon
			(pts
				(xy 332.83398 -300.520862) (xy 332.97241 -300.520862) (xy 332.972156 -286.63265) (xy 333.042006 -286.5628)
				(xy 333.042006 -282.06192) (xy 333.575406 -281.52852) (xy 333.575406 -280.15565) (xy 333.561944 -280.142188)
				(xy 333.47406 -280.142188) (xy 333.286354 -279.954482) (xy 333.286354 -279.8826) (xy 333.169514 -279.76576)
				(xy 332.894432 -279.76576) (xy 332.834234 -279.825958) (xy 332.6638 -279.825958) (xy 332.538324 -279.700482)
				(xy 332.50759 -279.700482) (xy 332.411832 -279.700482) (xy 332.005432 -279.294082) (xy 332.005432 -279.199848)
				(xy 332.183232 -279.022302) (xy 332.183232 -278.940768) (xy 331.832458 -278.589994) (xy 331.768958 -278.589994)
				(xy 331.596238 -278.762714) (xy 331.50556 -278.762714) (xy 330.525628 -277.782782) (xy 330.525628 -277.664164)
				(xy 332.59014 -275.599652) (xy 332.59014 -275.500338) (xy 331.727302 -274.6375) (xy 331.56525 -274.6375)
				(xy 331.18679 -274.25904) (xy 331.18679 -274.15871) (xy 331.407008 -273.938492) (xy 331.407008 -273.872198)
				(xy 331.085698 -273.550888) (xy 331.085698 -273.444716) (xy 331.239368 -273.291046) (xy 331.239368 -273.228816)
				(xy 331.043026 -273.032474) (xy 331.043026 -272.964148) (xy 332.267814 -271.73936) (xy 332.267814 -271.72158)
				(xy 332.116176 -271.569942) (xy 332.116176 -271.498314) (xy 332.564232 -271.050258) (xy 332.564232 -271.010634)
				(xy 332.145894 -270.592296) (xy 332.145894 -270.218662) (xy 331.533754 -269.606522) (xy 331.533754 -269.52067)
				(xy 331.891132 -269.163292) (xy 331.891132 -269.129764) (xy 331.738478 -268.97711) (xy 331.712316 -268.97711)
				(xy 331.162152 -269.527274) (xy 331.063092 -269.527274) (xy 330.69403 -269.158212) (xy 330.69403 -269.047468)
				(xy 331.328776 -268.412722) (xy 331.328776 -268.353286) (xy 330.963778 -267.988288) (xy 330.963778 -267.885164)
				(xy 331.271372 -267.57757) (xy 331.271372 -267.519912) (xy 331.112622 -267.361162) (xy 331.112622 -267.327888)
				(xy 331.18806 -267.25245) (xy 331.65796 -266.78255) (xy 331.929486 -266.511024) (xy 331.929486 -265.94181)
				(xy 331.713586 -265.72591) (xy 331.713586 -264.791952) (xy 331.636116 -264.714482) (xy 330.712064 -264.714482)
				(xy 330.474066 -264.476484) (xy 330.474066 -264.311892) (xy 330.541376 -264.244582) (xy 330.541376 -264.188702)
				(xy 330.394818 -264.042144) (xy 330.394818 -263.958832) (xy 330.491846 -263.861804) (xy 330.491846 -263.786366)
				(xy 330.35494 -263.64946) (xy 330.35494 -263.56437) (xy 330.497942 -263.421368) (xy 331.646022 -263.421368)
				(xy 331.685646 -263.381744) (xy 331.685646 -263.220962) (xy 331.64399 -263.179306) (xy 330.6445 -263.179306)
				(xy 330.54925 -263.084056) (xy 330.54925 -262.471662) (xy 330.640436 -262.380476) (xy 330.868528 -262.380476)
				(xy 330.896468 -262.352536) (xy 330.896468 -261.914132) (xy 330.856844 -261.874508) (xy 330.59497 -261.874508)
				(xy 330.539344 -261.818882) (xy 330.539344 -261.430262) (xy 330.614528 -261.355078) (xy 331.650086 -261.355078)
				(xy 331.673962 -261.378954) (xy 331.759052 -261.378954) (xy 331.872082 -261.265924) (xy 331.872082 -261.204456)
				(xy 331.790802 -261.123176) (xy 331.279246 -261.123176) (xy 331.21981 -261.06374) (xy 331.21981 -260.02234)
				(xy 331.31506 -259.92709) (xy 331.440282 -259.92709) (xy 331.61859 -259.748782) (xy 331.61859 -259.562092)
				(xy 331.67701 -259.503672) (xy 331.67701 -258.836922) (xy 331.56652 -258.726432) (xy 331.56652 -258.539234)
				(xy 331.60589 -258.499864) (xy 331.60589 -258.485132) (xy 331.605636 -258.485132) (xy 331.479398 -258.358894)
				(xy 331.479398 -258.315206) (xy 331.514958 -258.279646) (xy 331.514958 -258.142486) (xy 331.423772 -258.0513)
				(xy 331.423772 -257.991102) (xy 331.493114 -257.92176) (xy 331.559154 -257.85572) (xy 331.736954 -257.67792)
				(xy 332.966822 -257.67792) (xy 333.061818 -257.582924) (xy 333.061818 -257.394964) (xy 332.91907 -257.252216)
				(xy 332.614524 -257.252216) (xy 332.529434 -257.167126) (xy 332.529434 -257.02006) (xy 332.509876 -257.000502)
				(xy 332.24724 -257.000502) (xy 332.125828 -256.87909) (xy 332.125828 -256.336038) (xy 330.731876 -254.942086)
				(xy 330.731876 -254.746252) (xy 329.387454 -256.090674) (xy 322.120006 -256.090674) (xy 322.061586 -256.090674)
				(xy 322.061586 -256.417572) (xy 321.744086 -256.735072) (xy 321.744086 -257.108452) (xy 321.838066 -257.202432)
				(xy 322.323206 -257.202432) (xy 322.513706 -257.392932) (xy 322.767706 -257.392932) (xy 323.161406 -257.786632)
				(xy 323.400166 -257.786632) (xy 323.661786 -258.048252) (xy 323.974206 -258.048252) (xy 324.022466 -257.999992)
				(xy 324.578726 -257.999992) (xy 324.578726 -258.005072) (xy 324.741286 -258.167632) (xy 324.868286 -258.167632)
				(xy 325.322946 -258.622292) (xy 325.828406 -258.622292) (xy 326.067166 -258.861052) (xy 326.204326 -258.861052)
				(xy 326.537066 -259.193792) (xy 326.895206 -259.193792) (xy 327.161906 -259.460492) (xy 327.443846 -259.460492)
				(xy 327.723246 -259.739892) (xy 328.012806 -259.739892) (xy 328.371962 -260.099048) (xy 328.83475 -260.099048)
				(xy 328.990706 -260.255004) (xy 326.28332 -262.962644) (xy 324.34276 -264.903204) (xy 324.06336 -264.903204)
				(xy 324.000114 -264.903204) (xy 322.935092 -265.968226) (xy 322.935092 -266.03706) (xy 322.935092 -267.491972)
				(xy 322.49491 -267.932154) (xy 322.49491 -267.998956) (xy 323.857366 -269.361412) (xy 323.857366 -269.673578)
				(xy 324.0151 -269.831312) (xy 324.0151 -272.332704) (xy 323.58457 -272.763234) (xy 321.805554 -276.010624)
				(xy 321.805554 -276.775164) (xy 320.337434 -278.243284) (xy 320.309494 -278.271224) (xy 320.308986 -278.271224)
				(xy 320.035682 -278.544528) (xy 320.088006 -278.596852) (xy 321.909186 -280.418032) (xy 321.909186 -280.705052)
				(xy 322.076826 -280.872692) (xy 322.092066 -280.872692) (xy 322.549266 -281.329892) (xy 322.549266 -281.340052)
				(xy 322.384166 -281.505152) (xy 322.384166 -281.721052) (xy 323.057266 -282.394152) (xy 323.169026 -282.394152)
				(xy 323.708776 -282.933902) (xy 323.708776 -282.961842) (xy 323.352414 -283.318204) (xy 323.321426 -283.349192)
				(xy 323.321426 -283.399992) (xy 325.041514 -285.12008) (xy 325.041514 -285.489904) (xy 325.041514 -285.602172)
				(xy 325.498714 -286.059372) (xy 325.498714 -286.709104) (xy 325.501254 -286.711644) (xy 325.501254 -286.80156)
				(xy 326.025256 -287.325562) (xy 325.550022 -287.800796) (xy 325.550022 -288.026348) (xy 325.782686 -288.259012)
				(xy 326.008238 -288.259012) (xy 326.125332 -288.376106) (xy 326.125332 -289.18281) (xy 326.311514 -289.368992)
				(xy 326.044306 -289.6362) (xy 326.044306 -290.075112) (xy 327.525126 -291.555932) (xy 327.525126 -291.561012)
				(xy 327.324974 -291.76091) (xy 327.324974 -291.87902) (xy 328.063606 -292.617652) (xy 328.063606 -292.632892)
				(xy 328.033126 -292.663372) (xy 328.033126 -292.734492) (xy 328.525886 -293.227252) (xy 328.525886 -293.283132)
				(xy 328.267568 -293.541704) (xy 328.959718 -294.233854) (xy 328.502772 -294.6908) (xy 328.485246 -294.708326)
				(xy 328.485246 -294.791892) (xy 329.143106 -295.449752) (xy 329.143106 -295.503092) (xy 328.797158 -295.849294)
				(xy 328.797158 -295.952164) (xy 329.346306 -296.501312) (xy 329.346306 -296.613072) (xy 329.721718 -296.988484)
				(xy 329.721718 -297.026584) (xy 329.53071 -297.217846) (xy 329.519026 -297.22953) (xy 329.519026 -297.326812)
				(xy 332.713076 -300.520862)
			)
		)
	)
	(zone
		(layer "F.Cu")
		(hatch none 0.5)
		(connect_pads
			(clearance 0)
		)
		(min_thickness 0.25)
		(keepout
			(tracks not_allowed)
			(vias allowed)
			(pads allowed)
			(copperpour not_allowed)
			(footprints allowed)
		)
		(placement
			(enabled no)
			(sheetname "")
		)
		(fill
			(thermal_gap 0.5)
			(thermal_bridge_width 0.5)
			(island_removal_mode 0)
		)
		(polygon
			(pts
				(arc
					(start 378.100082 -22.29993)
					(mid 380.900178 -19.499834)
					(end 383.70002 -22.29993)
				)
				(arc
					(start 383.70002 -22.29993)
					(mid 380.900178 -25.099772)
					(end 378.100082 -22.29993)
				)
			)
		)
	)
	(zone
		(layer "F.Cu")
		(hatch none 0.5)
		(connect_pads
			(clearance 0)
		)
		(min_thickness 0.25)
		(keepout
			(tracks allowed)
			(vias allowed)
			(pads allowed)
			(copperpour allowed)
			(footprints allowed)
		)
		(placement
			(enabled no)
			(sheetname "")
		)
		(fill
			(thermal_gap 0.5)
			(thermal_bridge_width 0.5)
			(island_removal_mode 0)
		)
		(polygon
			(pts
				(xy 180.423058 -196.154802) (xy 180.423058 -195.926202) (xy 182.455058 -195.926202) (xy 182.455058 -196.154802)
			)
		)
	)
	(zone
		(layer "F.Cu")
		(hatch none 0.5)
		(connect_pads
			(clearance 0)
		)
		(min_thickness 0.25)
		(keepout
			(tracks allowed)
			(vias allowed)
			(pads allowed)
			(copperpour allowed)
			(footprints allowed)
		)
		(placement
			(enabled no)
			(sheetname "")
		)
		(fill
			(thermal_gap 0.5)
			(thermal_bridge_width 0.5)
			(island_removal_mode 0)
		)
		(polygon
			(pts
				(xy 445.493902 -270.95704) (xy 443.461902 -270.95704) (xy 443.461902 -270.954754) (xy 443.283086 -270.954754)
				(xy 443.283086 -270.717518) (xy 443.145164 -270.717518) (xy 443.101984 -270.674338) (xy 443.101984 -270.541496)
				(xy 443.101984 -270.237458) (xy 443.174628 -270.164814) (xy 445.714882 -270.164814) (xy 445.856106 -270.306038)
				(xy 445.856106 -270.503142) (xy 445.774572 -270.584676) (xy 445.774572 -270.95704) (xy 445.677036 -270.95704)
				(xy 445.630046 -270.95704)
			)
		)
	)
	(zone
		(layer "F.Cu")
		(hatch none 0.5)
		(connect_pads
			(clearance 0)
		)
		(min_thickness 0.25)
		(keepout
			(tracks allowed)
			(vias allowed)
			(pads allowed)
			(copperpour allowed)
			(footprints allowed)
		)
		(placement
			(enabled no)
			(sheetname "")
		)
		(fill
			(thermal_gap 0.5)
			(thermal_bridge_width 0.5)
			(island_removal_mode 0)
		)
		(polygon
			(pts
				(xy 14.560042 -226.86645) (xy 14.560042 -226.422712) (xy 16.885158 -226.422712) (xy 16.885158 -226.86645)
			)
		)
	)
	(zone
		(layer "F.Cu")
		(hatch none 0.5)
		(connect_pads
			(clearance 0)
		)
		(min_thickness 0.25)
		(keepout
			(tracks allowed)
			(vias allowed)
			(pads allowed)
			(copperpour allowed)
			(footprints allowed)
		)
		(placement
			(enabled no)
			(sheetname "")
		)
		(fill
			(thermal_gap 0.5)
			(thermal_bridge_width 0.5)
			(island_removal_mode 0)
		)
		(polygon
			(pts
				(xy 157.791658 -196.154802) (xy 157.791658 -195.926202) (xy 159.823658 -195.926202) (xy 159.823658 -196.154802)
			)
		)
	)
	(zone
		(layer "F.Cu")
		(hatch none 0.5)
		(connect_pads
			(clearance 0)
		)
		(min_thickness 0.25)
		(keepout
			(tracks allowed)
			(vias allowed)
			(pads allowed)
			(copperpour allowed)
			(footprints allowed)
		)
		(placement
			(enabled no)
			(sheetname "")
		)
		(fill
			(thermal_gap 0.5)
			(thermal_bridge_width 0.5)
			(island_removal_mode 0)
		)
		(polygon
			(pts
				(xy 259.056378 -285.516574) (xy 259.056378 -285.072836) (xy 261.381494 -285.072836) (xy 261.381494 -285.516574)
			)
		)
	)
	(zone
		(layer "F.Cu")
		(hatch none 0.5)
		(connect_pads
			(clearance 0)
		)
		(min_thickness 0.25)
		(keepout
			(tracks not_allowed)
			(vias allowed)
			(pads allowed)
			(copperpour not_allowed)
			(footprints allowed)
		)
		(placement
			(enabled no)
			(sheetname "")
		)
		(fill
			(thermal_gap 0.5)
			(thermal_bridge_width 0.5)
			(island_removal_mode 0)
		)
		(polygon
			(pts
				(xy 326.602598 -343.284048) (xy 326.844914 -343.284048) (xy 326.844914 -343.223342) (xy 327.36282 -343.223342)
				(xy 327.36282 -342.930226) (xy 326.842628 -342.930226) (xy 326.842628 -342.709754) (xy 326.146922 -342.709754)
				(xy 326.146922 -342.836754) (xy 326.602598 -342.836754)
			)
		)
	)
	(zone
		(layer "F.Cu")
		(hatch none 0.5)
		(connect_pads
			(clearance 0)
		)
		(min_thickness 0.25)
		(keepout
			(tracks allowed)
			(vias allowed)
			(pads allowed)
			(copperpour allowed)
			(footprints allowed)
		)
		(placement
			(enabled no)
			(sheetname "")
		)
		(fill
			(thermal_gap 0.5)
			(thermal_bridge_width 0.5)
			(island_removal_mode 0)
		)
		(polygon
			(pts
				(xy 458.538326 -306.654962) (xy 458.538326 -306.426362) (xy 460.570326 -306.426362) (xy 460.570326 -306.654962)
			)
		)
	)
	(zone
		(layer "F.Cu")
		(hatch none 0.5)
		(connect_pads
			(clearance 0)
		)
		(min_thickness 0.25)
		(keepout
			(tracks allowed)
			(vias allowed)
			(pads allowed)
			(copperpour allowed)
			(footprints allowed)
		)
		(placement
			(enabled no)
			(sheetname "")
		)
		(fill
			(thermal_gap 0.5)
			(thermal_bridge_width 0.5)
			(island_removal_mode 0)
		)
		(polygon
			(pts
				(xy 63.977012 -262.566658) (xy 63.977012 -262.12292) (xy 66.186812 -262.12292) (xy 66.186812 -262.566658)
			)
		)
	)
	(zone
		(layer "F.Cu")
		(hatch none 0.5)
		(connect_pads
			(clearance 0)
		)
		(min_thickness 0.25)
		(keepout
			(tracks allowed)
			(vias allowed)
			(pads allowed)
			(copperpour allowed)
			(footprints allowed)
		)
		(placement
			(enabled no)
			(sheetname "")
		)
		(fill
			(thermal_gap 0.5)
			(thermal_bridge_width 0.5)
			(island_removal_mode 0)
		)
		(polygon
			(pts
				(xy 428.363126 -235.2548) (xy 428.363126 -235.0262) (xy 430.395126 -235.0262) (xy 430.395126 -235.2548)
			)
		)
	)
	(zone
		(layer "F.Cu")
		(hatch none 0.5)
		(connect_pads
			(clearance 0)
		)
		(min_thickness 0.25)
		(keepout
			(tracks allowed)
			(vias allowed)
			(pads allowed)
			(copperpour allowed)
			(footprints allowed)
		)
		(placement
			(enabled no)
			(sheetname "")
		)
		(fill
			(thermal_gap 0.5)
			(thermal_bridge_width 0.5)
			(island_removal_mode 0)
		)
		(polygon
			(pts
				(xy 432.20513 -319.243202) (xy 432.20513 -316.881002) (xy 434.82133 -316.881002) (xy 434.82133 -319.243202)
			)
		)
	)
	(zone
		(layer "F.Cu")
		(hatch none 0.5)
		(connect_pads
			(clearance 0)
		)
		(min_thickness 0.25)
		(keepout
			(tracks allowed)
			(vias allowed)
			(pads allowed)
			(copperpour allowed)
			(footprints allowed)
		)
		(placement
			(enabled no)
			(sheetname "")
		)
		(fill
			(thermal_gap 0.5)
			(thermal_bridge_width 0.5)
			(island_removal_mode 0)
		)
		(polygon
			(pts
				(xy 59.822842 -231.966516) (xy 59.822842 -231.522778) (xy 62.147958 -231.522778) (xy 62.147958 -231.966516)
			)
		)
	)
	(zone
		(layer "F.Cu")
		(hatch none 0.5)
		(connect_pads
			(clearance 0)
		)
		(min_thickness 0.25)
		(keepout
			(tracks allowed)
			(vias allowed)
			(pads allowed)
			(copperpour allowed)
			(footprints allowed)
		)
		(placement
			(enabled no)
			(sheetname "")
		)
		(fill
			(thermal_gap 0.5)
			(thermal_bridge_width 0.5)
			(island_removal_mode 0)
		)
		(polygon
			(pts
				(xy 41.29151 -277.016464) (xy 41.29151 -276.572726) (xy 43.616626 -276.572726) (xy 43.616626 -277.016464)
			)
		)
	)
	(zone
		(layer "F.Cu")
		(hatch none 0.5)
		(connect_pads
			(clearance 0)
		)
		(min_thickness 0.25)
		(keepout
			(tracks allowed)
			(vias allowed)
			(pads allowed)
			(copperpour allowed)
			(footprints allowed)
		)
		(placement
			(enabled no)
			(sheetname "")
		)
		(fill
			(thermal_gap 0.5)
			(thermal_bridge_width 0.5)
			(island_removal_mode 0)
		)
		(polygon
			(pts
				(xy 307.76291 -265.116564) (xy 307.76291 -264.672826) (xy 310.088026 -264.672826) (xy 310.088026 -265.116564)
			)
		)
	)
	(zone
		(layer "F.Cu")
		(hatch none 0.5)
		(connect_pads
			(clearance 0)
		)
		(min_thickness 0.25)
		(keepout
			(tracks not_allowed)
			(vias allowed)
			(pads allowed)
			(copperpour not_allowed)
			(footprints allowed)
		)
		(placement
			(enabled no)
			(sheetname "")
		)
		(fill
			(thermal_gap 0.5)
			(thermal_bridge_width 0.5)
			(island_removal_mode 0)
		)
		(polygon
			(pts
				(xy 41.50106 -393.93114) (xy 41.50106 -393.7635) (xy 38.55466 -393.7635) (xy 38.55466 -393.93114)
			)
		)
	)
	(zone
		(layer "F.Cu")
		(hatch none 0.5)
		(connect_pads
			(clearance 0)
		)
		(min_thickness 0.25)
		(keepout
			(tracks allowed)
			(vias allowed)
			(pads allowed)
			(copperpour allowed)
			(footprints not_allowed)
		)
		(placement
			(enabled no)
			(sheetname "")
		)
		(fill
			(thermal_gap 0.5)
			(thermal_bridge_width 0.5)
			(island_removal_mode 0)
		)
		(polygon
			(pts
				(xy 113.154968 -72.00011) (xy 133.225032 -72.00011) (xy 133.225032 -69.499988) (xy 113.154968 -69.499988)
			)
		)
	)
	(zone
		(layer "F.Cu")
		(hatch none 0.5)
		(connect_pads
			(clearance 0)
		)
		(min_thickness 0.25)
		(keepout
			(tracks allowed)
			(vias allowed)
			(pads allowed)
			(copperpour allowed)
			(footprints allowed)
		)
		(placement
			(enabled no)
			(sheetname "")
		)
		(fill
			(thermal_gap 0.5)
			(thermal_bridge_width 0.5)
			(island_removal_mode 0)
		)
		(polygon
			(pts
				(xy 51.932332 -410.948886) (xy 51.932332 -406.105868) (xy 53.816758 -406.105868) (xy 53.816758 -410.948886)
			)
		)
	)
	(zone
		(layer "F.Cu")
		(hatch none 0.5)
		(connect_pads
			(clearance 0)
		)
		(min_thickness 0.25)
		(keepout
			(tracks allowed)
			(vias allowed)
			(pads allowed)
			(copperpour allowed)
			(footprints allowed)
		)
		(placement
			(enabled no)
			(sheetname "")
		)
		(fill
			(thermal_gap 0.5)
			(thermal_bridge_width 0.5)
			(island_removal_mode 0)
		)
		(polygon
			(pts
				(xy 192.066926 -205.27645) (xy 194.098926 -205.27645) (xy 194.098926 -205.50505) (xy 192.066926 -205.50505)
				(xy 191.930782 -205.50505) (xy 191.883792 -205.50505) (xy 191.883792 -205.27645) (xy 191.930782 -205.27645)
			)
		)
	)
	(zone
		(layer "F.Cu")
		(hatch none 0.5)
		(connect_pads
			(clearance 0)
		)
		(min_thickness 0.25)
		(keepout
			(tracks allowed)
			(vias allowed)
			(pads allowed)
			(copperpour allowed)
			(footprints not_allowed)
		)
		(placement
			(enabled no)
			(sheetname "")
		)
		(fill
			(thermal_gap 0.5)
			(thermal_bridge_width 0.5)
			(island_removal_mode 0)
		)
		(polygon
			(pts
				(arc
					(start 273.645376 -51.999896)
					(mid 268.645386 -56.999886)
					(end 263.645396 -51.999896)
				)
				(arc
					(start 263.645396 -51.999896)
					(mid 268.645386 -46.999906)
					(end 273.645376 -51.999896)
				)
			)
		)
	)
	(zone
		(layer "F.Cu")
		(hatch none 0.5)
		(connect_pads
			(clearance 0)
		)
		(min_thickness 0.25)
		(keepout
			(tracks allowed)
			(vias allowed)
			(pads allowed)
			(copperpour allowed)
			(footprints allowed)
		)
		(placement
			(enabled no)
			(sheetname "")
		)
		(fill
			(thermal_gap 0.5)
			(thermal_bridge_width 0.5)
			(island_removal_mode 0)
		)
		(polygon
			(pts
				(xy 207.154526 -266.476226) (xy 209.186526 -266.476226) (xy 209.186526 -266.704826) (xy 207.154526 -266.704826)
				(xy 206.987902 -266.704826) (xy 206.893668 -266.704826) (xy 206.893668 -266.476226) (xy 206.987902 -266.476226)
			)
		)
	)
	(zone
		(layer "F.Cu")
		(hatch none 0.5)
		(connect_pads
			(clearance 0)
		)
		(min_thickness 0.25)
		(keepout
			(tracks allowed)
			(vias allowed)
			(pads allowed)
			(copperpour allowed)
			(footprints allowed)
		)
		(placement
			(enabled no)
			(sheetname "")
		)
		(fill
			(thermal_gap 0.5)
			(thermal_bridge_width 0.5)
			(island_removal_mode 0)
		)
		(polygon
			(pts
				(xy 277.58771 -289.766502) (xy 277.58771 -289.322764) (xy 279.912826 -289.322764) (xy 279.912826 -289.766502)
			)
		)
	)
	(zone
		(layer "F.Cu")
		(hatch none 0.5)
		(connect_pads
			(clearance 0)
		)
		(min_thickness 0.25)
		(keepout
			(tracks allowed)
			(vias allowed)
			(pads allowed)
			(copperpour allowed)
			(footprints allowed)
		)
		(placement
			(enabled no)
			(sheetname "")
		)
		(fill
			(thermal_gap 0.5)
			(thermal_bridge_width 0.5)
			(island_removal_mode 0)
		)
		(polygon
			(pts
				(xy 332.827884 -259.280152) (xy 333.03083 -259.077206) (xy 333.03083 -259.03428) (xy 332.587346 -258.590542)
				(xy 332.465172 -258.590542) (xy 332.332076 -258.723384) (xy 332.332076 -258.827524) (xy 332.784704 -259.280152)
			)
		)
	)
	(zone
		(layer "F.Cu")
		(hatch none 0.5)
		(connect_pads
			(clearance 0)
		)
		(min_thickness 0.25)
		(keepout
			(tracks allowed)
			(vias allowed)
			(pads allowed)
			(copperpour allowed)
			(footprints allowed)
		)
		(placement
			(enabled no)
			(sheetname "")
		)
		(fill
			(thermal_gap 0.5)
			(thermal_bridge_width 0.5)
			(island_removal_mode 0)
		)
		(polygon
			(pts
				(xy 351.568512 -63.431674) (xy 350.39808 -63.431674) (xy 347.83268 -63.431674) (xy 346.61348 -63.431674)
				(xy 346.30868 -63.736474) (xy 346.30868 -64.193674) (xy 346.00388 -64.498474) (xy 345.69908 -64.498474)
				(xy 345.69908 -65.260474) (xy 344.93708 -66.022474) (xy 344.93708 -68.333874) (xy 344.65768 -68.613274)
				(xy 338.84108 -68.613274) (xy 337.92668 -68.613274) (xy 337.31708 -68.003674) (xy 337.31708 -64.498474)
				(xy 337.16468 -64.346074) (xy 335.33588 -64.346074) (xy 334.57388 -65.108074) (xy 334.57388 -67.089274)
				(xy 333.24038 -68.423028) (xy 333.157068 -68.339716) (xy 331.798168 -68.339716) (xy 330.116688 -66.658236)
				(xy 326.596248 -66.658236) (xy 321.61988 -61.681868) (xy 321.61988 -52.736242) (xy 320.845434 -51.961796)
				(xy 320.7512 -51.961796) (xy 319.708022 -50.918618) (xy 319.708022 -48.976788) (xy 320.401188 -48.283622)
				(xy 320.401188 -47.387256) (xy 320.401188 -41.485566) (xy 320.00825 -41.092628) (xy 320.00825 -38.994842)
				(xy 321.868292 -37.1348) (xy 324.569582 -37.1348) (xy 327.270364 -34.434018) (xy 327.270364 -33.214564)
				(xy 326.88276 -32.82696) (xy 326.88276 -31.854648) (xy 326.850248 -31.822136) (xy 326.850248 -30.572456)
				(xy 327.4949 -29.927804) (xy 328.122534 -29.30017) (xy 328.464164 -28.95854) (xy 333.392526 -28.95854)
				(xy 333.734156 -29.30017) (xy 335.389474 -29.30017) (xy 336.017108 -29.927804) (xy 344.103706 -29.927804)
				(xy 345.034616 -29.927804) (xy 346.31376 -31.206948) (xy 346.31376 -32.137858) (xy 346.92971 -32.753808)
				(xy 352.03384 -32.753808) (xy 352.764598 -33.484566) (xy 352.764598 -35.71113) (xy 354.925376 -37.871908)
				(xy 354.925376 -44.318428) (xy 356.490016 -45.883068) (xy 357.95712 -45.883068) (xy 358.648 -46.573948)
				(xy 358.648 -48.986948) (xy 358.394 -49.240948) (xy 358.394 -49.875948) (xy 358.394 -51.018948)
				(xy 357.632 -51.780948) (xy 357.632 -52.415948) (xy 357.759 -52.542948) (xy 357.759 -53.177948)
				(xy 357.632 -53.304948) (xy 355.621082 -53.304948) (xy 355.367082 -53.558948) (xy 355.367082 -59.633104)
				(xy 354.079302 -60.920884)
			)
		)
	)
	(zone
		(layer "F.Cu")
		(hatch none 0.5)
		(connect_pads
			(clearance 0)
		)
		(min_thickness 0.25)
		(keepout
			(tracks allowed)
			(vias allowed)
			(pads allowed)
			(copperpour allowed)
			(footprints not_allowed)
		)
		(placement
			(enabled no)
			(sheetname "")
		)
		(fill
			(thermal_gap 0.5)
			(thermal_bridge_width 0.5)
			(island_removal_mode 0)
		)
		(polygon
			(pts
				(xy 242.149884 -41.924986) (xy 242.149884 -36.924996) (xy 237.949994 -36.924996) (xy 237.949994 -41.924986)
			)
		)
	)
	(zone
		(layer "F.Cu")
		(hatch none 0.5)
		(connect_pads
			(clearance 0)
		)
		(min_thickness 0.25)
		(keepout
			(tracks allowed)
			(vias allowed)
			(pads allowed)
			(copperpour allowed)
			(footprints allowed)
		)
		(placement
			(enabled no)
			(sheetname "")
		)
		(fill
			(thermal_gap 0.5)
			(thermal_bridge_width 0.5)
			(island_removal_mode 0)
		)
		(polygon
			(pts
				(xy 349.504 -67.274948) (xy 349.504 -65.776348) (xy 348.69628 -65.776348) (xy 348.4626 -65.776348)
				(xy 348.361 -65.877948) (xy 348.361 -67.147948) (xy 348.488 -67.274948) (xy 348.615 -67.274948)
			)
		)
	)
	(zone
		(layer "F.Cu")
		(hatch none 0.5)
		(connect_pads
			(clearance 0)
		)
		(min_thickness 0.25)
		(keepout
			(tracks allowed)
			(vias allowed)
			(pads allowed)
			(copperpour allowed)
			(footprints allowed)
		)
		(placement
			(enabled no)
			(sheetname "")
		)
		(fill
			(thermal_gap 0.5)
			(thermal_bridge_width 0.5)
			(island_removal_mode 0)
		)
		(polygon
			(pts
				(xy 210.598258 -217.40495) (xy 210.598258 -217.17635) (xy 212.630258 -217.17635) (xy 212.630258 -217.40495)
			)
		)
	)
	(zone
		(layer "F.Cu")
		(hatch none 0.5)
		(connect_pads
			(clearance 0)
		)
		(min_thickness 0.25)
		(keepout
			(tracks allowed)
			(vias allowed)
			(pads allowed)
			(copperpour allowed)
			(footprints allowed)
		)
		(placement
			(enabled no)
			(sheetname "")
		)
		(fill
			(thermal_gap 0.5)
			(thermal_bridge_width 0.5)
			(island_removal_mode 0)
		)
		(polygon
			(pts
				(xy 277.58771 -301.666656) (xy 277.58771 -301.222918) (xy 279.912826 -301.222918) (xy 279.912826 -301.666656)
			)
		)
	)
	(zone
		(layer "F.Cu")
		(hatch none 0.5)
		(connect_pads
			(clearance 0)
		)
		(min_thickness 0.25)
		(keepout
			(tracks allowed)
			(vias allowed)
			(pads allowed)
			(copperpour allowed)
			(footprints allowed)
		)
		(placement
			(enabled no)
			(sheetname "")
		)
		(fill
			(thermal_gap 0.5)
			(thermal_bridge_width 0.5)
			(island_removal_mode 0)
		)
		(polygon
			(pts
				(xy 445.493902 -235.256832) (xy 443.461902 -235.256832) (xy 443.461902 -235.254546) (xy 443.283086 -235.254546)
				(xy 443.283086 -235.01731) (xy 443.145164 -235.01731) (xy 443.101984 -234.97413) (xy 443.101984 -234.841288)
				(xy 443.101984 -234.53725) (xy 443.174628 -234.464606) (xy 445.714882 -234.464606) (xy 445.856106 -234.60583)
				(xy 445.856106 -234.802934) (xy 445.774572 -234.884468) (xy 445.774572 -235.256832) (xy 445.677036 -235.256832)
				(xy 445.630046 -235.256832)
			)
		)
	)
	(zone
		(layer "F.Cu")
		(hatch none 0.5)
		(connect_pads
			(clearance 0)
		)
		(min_thickness 0.25)
		(keepout
			(tracks allowed)
			(vias allowed)
			(pads allowed)
			(copperpour allowed)
			(footprints allowed)
		)
		(placement
			(enabled no)
			(sheetname "")
		)
		(fill
			(thermal_gap 0.5)
			(thermal_bridge_width 0.5)
			(island_removal_mode 0)
		)
		(polygon
			(pts
				(xy 41.29151 -275.316442) (xy 41.29151 -274.872704) (xy 43.616626 -274.872704) (xy 43.616626 -275.316442)
			)
		)
	)
	(zone
		(layer "F.Cu")
		(hatch none 0.5)
		(connect_pads
			(clearance 0)
		)
		(min_thickness 0.25)
		(keepout
			(tracks allowed)
			(vias allowed)
			(pads allowed)
			(copperpour allowed)
			(footprints allowed)
		)
		(placement
			(enabled no)
			(sheetname "")
		)
		(fill
			(thermal_gap 0.5)
			(thermal_bridge_width 0.5)
			(island_removal_mode 0)
		)
		(polygon
			(pts
				(xy 195.510658 -250.554998) (xy 195.510658 -250.326398) (xy 197.542658 -250.326398) (xy 197.542658 -250.554998)
			)
		)
	)
	(zone
		(layer "F.Cu")
		(hatch none 0.5)
		(connect_pads
			(clearance 0)
		)
		(min_thickness 0.25)
		(keepout
			(tracks allowed)
			(vias allowed)
			(pads allowed)
			(copperpour allowed)
			(footprints allowed)
		)
		(placement
			(enabled no)
			(sheetname "")
		)
		(fill
			(thermal_gap 0.5)
			(thermal_bridge_width 0.5)
			(island_removal_mode 0)
		)
		(polygon
			(pts
				(xy 180.423058 -224.204784) (xy 180.423058 -223.976184) (xy 182.455058 -223.976184) (xy 182.455058 -224.204784)
			)
		)
	)
	(zone
		(layer "F.Cu")
		(hatch none 0.5)
		(connect_pads
			(clearance 0)
		)
		(min_thickness 0.25)
		(keepout
			(tracks allowed)
			(vias allowed)
			(pads allowed)
			(copperpour allowed)
			(footprints allowed)
		)
		(placement
			(enabled no)
			(sheetname "")
		)
		(fill
			(thermal_gap 0.5)
			(thermal_bridge_width 0.5)
			(island_removal_mode 0)
		)
		(polygon
			(pts
				(xy 195.510658 -308.354984) (xy 195.510658 -308.126384) (xy 197.542658 -308.126384) (xy 197.542658 -308.354984)
			)
		)
	)
	(zone
		(layer "F.Cu")
		(hatch none 0.5)
		(connect_pads
			(clearance 0)
		)
		(min_thickness 0.25)
		(keepout
			(tracks allowed)
			(vias allowed)
			(pads allowed)
			(copperpour allowed)
			(footprints not_allowed)
		)
		(placement
			(enabled no)
			(sheetname "")
		)
		(fill
			(thermal_gap 0.5)
			(thermal_bridge_width 0.5)
			(island_removal_mode 0)
		)
		(polygon
			(pts
				(xy 319.86982 -191.77) (xy 319.86982 -311.770014) (xy 399.869914 -311.770014) (xy 399.869914 -191.77)
			)
		)
	)
	(zone
		(layer "F.Cu")
		(hatch none 0.5)
		(connect_pads
			(clearance 0)
		)
		(min_thickness 0.25)
		(keepout
			(tracks allowed)
			(vias allowed)
			(pads allowed)
			(copperpour allowed)
			(footprints allowed)
		)
		(placement
			(enabled no)
			(sheetname "")
		)
		(fill
			(thermal_gap 0.5)
			(thermal_bridge_width 0.5)
			(island_removal_mode 0)
		)
		(polygon
			(pts
				(xy 195.510658 -314.304934) (xy 195.510658 -314.076334) (xy 197.542658 -314.076334) (xy 197.542658 -314.304934)
			)
		)
	)
	(zone
		(layer "F.Cu")
		(hatch none 0.5)
		(connect_pads
			(clearance 0)
		)
		(min_thickness 0.25)
		(keepout
			(tracks allowed)
			(vias allowed)
			(pads allowed)
			(copperpour allowed)
			(footprints allowed)
		)
		(placement
			(enabled no)
			(sheetname "")
		)
		(fill
			(thermal_gap 0.5)
			(thermal_bridge_width 0.5)
			(island_removal_mode 0)
		)
		(polygon
			(pts
				(xy 415.027364 -20.04822) (xy 415.027364 -16.913606) (xy 416.806126 -16.913606) (xy 416.806126 -20.04822)
			)
		)
	)
	(zone
		(layer "F.Cu")
		(hatch none 0.5)
		(connect_pads
			(clearance 0)
		)
		(min_thickness 0.25)
		(keepout
			(tracks allowed)
			(vias allowed)
			(pads allowed)
			(copperpour allowed)
			(footprints allowed)
		)
		(placement
			(enabled no)
			(sheetname "")
		)
		(fill
			(thermal_gap 0.5)
			(thermal_bridge_width 0.5)
			(island_removal_mode 0)
		)
		(polygon
			(pts
				(xy 210.598258 -250.554998) (xy 210.598258 -250.326398) (xy 212.630258 -250.326398) (xy 212.630258 -250.554998)
			)
		)
	)
	(zone
		(layer "F.Cu")
		(hatch none 0.5)
		(connect_pads
			(clearance 0)
		)
		(min_thickness 0.25)
		(keepout
			(tracks allowed)
			(vias allowed)
			(pads allowed)
			(copperpour allowed)
			(footprints not_allowed)
		)
		(placement
			(enabled no)
			(sheetname "")
		)
		(fill
			(thermal_gap 0.5)
			(thermal_bridge_width 0.5)
			(island_removal_mode 0)
		)
		(polygon
			(pts
				(xy 378.420884 -363.21492) (xy 390.488678 -363.21492) (xy 390.488678 -348.836234) (xy 378.420884 -348.836234)
			)
		)
	)
	(zone
		(layer "F.Cu")
		(hatch none 0.5)
		(connect_pads
			(clearance 0)
		)
		(min_thickness 0.25)
		(keepout
			(tracks allowed)
			(vias allowed)
			(pads allowed)
			(copperpour allowed)
			(footprints allowed)
		)
		(placement
			(enabled no)
			(sheetname "")
		)
		(fill
			(thermal_gap 0.5)
			(thermal_bridge_width 0.5)
			(island_removal_mode 0)
		)
		(polygon
			(pts
				(xy 43.69562 -5.964428) (xy 43.69562 -4.036568) (xy 45.73016 -4.036568) (xy 45.73016 -5.964428)
			)
		)
	)
	(zone
		(layer "F.Cu")
		(hatch none 0.5)
		(connect_pads
			(clearance 0)
		)
		(min_thickness 0.25)
		(keepout
			(tracks allowed)
			(vias allowed)
			(pads allowed)
			(copperpour allowed)
			(footprints allowed)
		)
		(placement
			(enabled no)
			(sheetname "")
		)
		(fill
			(thermal_gap 0.5)
			(thermal_bridge_width 0.5)
			(island_removal_mode 0)
		)
		(polygon
			(pts
				(xy 277.58771 -302.51654) (xy 277.58771 -302.072802) (xy 279.912826 -302.072802) (xy 279.912826 -302.51654)
			)
		)
	)
	(zone
		(layer "F.Cu")
		(hatch none 0.5)
		(connect_pads
			(clearance 0)
		)
		(min_thickness 0.25)
		(keepout
			(tracks not_allowed)
			(vias allowed)
			(pads allowed)
			(copperpour not_allowed)
			(footprints allowed)
		)
		(placement
			(enabled no)
			(sheetname "")
		)
		(fill
			(thermal_gap 0.5)
			(thermal_bridge_width 0.5)
			(island_removal_mode 0)
		)
		(polygon
			(pts
				(arc
					(start 432.565048 -66.06794)
					(mid 426.803058 -60.30595)
					(end 421.041068 -66.06794)
				)
				(arc
					(start 421.041068 -74.767948)
					(mid 426.803058 -80.529938)
					(end 432.565048 -74.767948)
				)
			)
		)
	)
	(zone
		(layer "F.Cu")
		(hatch none 0.5)
		(connect_pads
			(clearance 0)
		)
		(min_thickness 0.25)
		(keepout
			(tracks allowed)
			(vias allowed)
			(pads allowed)
			(copperpour allowed)
			(footprints allowed)
		)
		(placement
			(enabled no)
			(sheetname "")
		)
		(fill
			(thermal_gap 0.5)
			(thermal_bridge_width 0.5)
			(island_removal_mode 0)
		)
		(polygon
			(pts
				(xy 157.791658 -234.176316) (xy 159.823658 -234.176316) (xy 159.971486 -234.176316) (xy 159.971486 -234.892342)
				(xy 157.621986 -234.892342) (xy 157.621986 -234.176316)
			)
		)
	)
	(zone
		(layer "F.Cu")
		(hatch none 0.5)
		(connect_pads
			(clearance 0)
		)
		(min_thickness 0.25)
		(keepout
			(tracks allowed)
			(vias allowed)
			(pads allowed)
			(copperpour allowed)
			(footprints allowed)
		)
		(placement
			(enabled no)
			(sheetname "")
		)
		(fill
			(thermal_gap 0.5)
			(thermal_bridge_width 0.5)
			(island_removal_mode 0)
		)
		(polygon
			(pts
				(xy 180.423058 -202.105006) (xy 180.423058 -201.876406) (xy 182.455058 -201.876406) (xy 182.455058 -202.105006)
			)
		)
	)
	(zone
		(layer "F.Cu")
		(hatch none 0.5)
		(connect_pads
			(clearance 0)
		)
		(min_thickness 0.25)
		(keepout
			(tracks allowed)
			(vias allowed)
			(pads allowed)
			(copperpour allowed)
			(footprints allowed)
		)
		(placement
			(enabled no)
			(sheetname "")
		)
		(fill
			(thermal_gap 0.5)
			(thermal_bridge_width 0.5)
			(island_removal_mode 0)
		)
		(polygon
			(pts
				(xy 350.869758 -321.385184) (xy 350.869758 -319.083944) (xy 355.241098 -319.083944) (xy 355.241098 -321.385184)
			)
		)
	)
	(zone
		(layer "F.Cu")
		(hatch none 0.5)
		(connect_pads
			(clearance 0)
		)
		(min_thickness 0.25)
		(keepout
			(tracks allowed)
			(vias allowed)
			(pads allowed)
			(copperpour allowed)
			(footprints not_allowed)
		)
		(placement
			(enabled no)
			(sheetname "")
		)
		(fill
			(thermal_gap 0.5)
			(thermal_bridge_width 0.5)
			(island_removal_mode 0)
		)
		(polygon
			(pts
				(xy 323.864986 -363.21492) (xy 335.848706 -363.21492) (xy 335.848706 -348.836234) (xy 323.864986 -348.836234)
			)
		)
	)
	(zone
		(layer "F.Cu")
		(hatch none 0.5)
		(connect_pads
			(clearance 0)
		)
		(min_thickness 0.25)
		(keepout
			(tracks allowed)
			(vias allowed)
			(pads allowed)
			(copperpour allowed)
			(footprints not_allowed)
		)
		(placement
			(enabled no)
			(sheetname "")
		)
		(fill
			(thermal_gap 0.5)
			(thermal_bridge_width 0.5)
			(island_removal_mode 0)
		)
		(polygon
			(pts
				(xy 52.403502 -330.091796) (xy 58.503312 -330.091796) (xy 58.503312 -186.09183) (xy 52.403502 -186.09183)
			)
		)
	)
	(zone
		(layer "F.Cu")
		(hatch none 0.5)
		(connect_pads
			(clearance 0)
		)
		(min_thickness 0.25)
		(keepout
			(tracks allowed)
			(vias allowed)
			(pads allowed)
			(copperpour allowed)
			(footprints allowed)
		)
		(placement
			(enabled no)
			(sheetname "")
		)
		(fill
			(thermal_gap 0.5)
			(thermal_bridge_width 0.5)
			(island_removal_mode 0)
		)
		(polygon
			(pts
				(xy 41.29151 -295.716452) (xy 41.29151 -295.272714) (xy 43.616626 -295.272714) (xy 43.616626 -295.716452)
			)
		)
	)
	(zone
		(layer "F.Cu")
		(hatch none 0.5)
		(connect_pads
			(clearance 0)
		)
		(min_thickness 0.25)
		(keepout
			(tracks allowed)
			(vias allowed)
			(pads allowed)
			(copperpour allowed)
			(footprints not_allowed)
		)
		(placement
			(enabled no)
			(sheetname "")
		)
		(fill
			(thermal_gap 0.5)
			(thermal_bridge_width 0.5)
			(island_removal_mode 0)
		)
		(polygon
			(pts
				(arc
					(start 388.899908 -22.29993)
					(mid 380.899924 -30.299914)
					(end 372.89994 -22.29993)
				)
				(arc
					(start 372.89994 -22.29993)
					(mid 380.899924 -14.299946)
					(end 388.899908 -22.29993)
				)
			)
		)
	)
	(zone
		(layer "F.Cu")
		(hatch none 0.5)
		(connect_pads
			(clearance 0)
		)
		(min_thickness 0.25)
		(keepout
			(tracks allowed)
			(vias allowed)
			(pads allowed)
			(copperpour allowed)
			(footprints allowed)
		)
		(placement
			(enabled no)
			(sheetname "")
		)
		(fill
			(thermal_gap 0.5)
			(thermal_bridge_width 0.5)
			(island_removal_mode 0)
		)
		(polygon
			(pts
				(xy 11.11631 -306.766468) (xy 11.11631 -306.32273) (xy 13.441426 -306.32273) (xy 13.441426 -306.766468)
			)
		)
	)
	(zone
		(layer "F.Cu")
		(hatch none 0.5)
		(connect_pads
			(clearance 0)
		)
		(min_thickness 0.25)
		(keepout
			(tracks allowed)
			(vias allowed)
			(pads allowed)
			(copperpour allowed)
			(footprints allowed)
		)
		(placement
			(enabled no)
			(sheetname "")
		)
		(fill
			(thermal_gap 0.5)
			(thermal_bridge_width 0.5)
			(island_removal_mode 0)
		)
		(polygon
			(pts
				(xy 165.335458 -197.854824) (xy 165.335458 -197.626224) (xy 167.367458 -197.626224) (xy 167.367458 -197.854824)
			)
		)
	)
	(zone
		(layer "F.Cu")
		(hatch none 0.5)
		(connect_pads
			(clearance 0)
		)
		(min_thickness 0.25)
		(keepout
			(tracks allowed)
			(vias allowed)
			(pads allowed)
			(copperpour allowed)
			(footprints allowed)
		)
		(placement
			(enabled no)
			(sheetname "")
		)
		(fill
			(thermal_gap 0.5)
			(thermal_bridge_width 0.5)
			(island_removal_mode 0)
		)
		(polygon
			(pts
				(xy 136.9822 -284.932628) (xy 137.26922 -284.932628) (xy 137.2997 -284.902148) (xy 137.2997 -284.274768)
				(xy 137.21334 -284.188408) (xy 137.02538 -284.188408) (xy 136.95172 -284.262068) (xy 136.95172 -284.902148)
			)
		)
	)
	(zone
		(layer "F.Cu")
		(hatch none 0.5)
		(connect_pads
			(clearance 0)
		)
		(min_thickness 0.25)
		(keepout
			(tracks allowed)
			(vias allowed)
			(pads allowed)
			(copperpour allowed)
			(footprints not_allowed)
		)
		(placement
			(enabled no)
			(sheetname "")
		)
		(fill
			(thermal_gap 0.5)
			(thermal_bridge_width 0.5)
			(island_removal_mode 0)
		)
		(polygon
			(pts
				(xy 304.47996 -382.770126) (xy 281.480006 -382.770126) (xy 281.480006 -433.07)
				(arc
					(start 285.960566 -433.07)
					(mid 293.550046 -427.599957)
					(end 301.139352 -433.07)
				)
				(xy 304.47996 -433.07)
			)
		)
	)
	(zone
		(layer "F.Cu")
		(hatch none 0.5)
		(connect_pads
			(clearance 0)
		)
		(min_thickness 0.25)
		(keepout
			(tracks allowed)
			(vias allowed)
			(pads allowed)
			(copperpour allowed)
			(footprints allowed)
		)
		(placement
			(enabled no)
			(sheetname "")
		)
		(fill
			(thermal_gap 0.5)
			(thermal_bridge_width 0.5)
			(island_removal_mode 0)
		)
		(polygon
			(pts
				(xy 246.91848 -396.499588) (xy 246.91848 -393.172188) (xy 250.30176 -393.172188) (xy 250.30176 -396.499588)
			)
		)
	)
	(zone
		(layer "F.Cu")
		(hatch none 0.5)
		(connect_pads
			(clearance 0)
		)
		(min_thickness 0.25)
		(keepout
			(tracks allowed)
			(vias allowed)
			(pads allowed)
			(copperpour allowed)
			(footprints allowed)
		)
		(placement
			(enabled no)
			(sheetname "")
		)
		(fill
			(thermal_gap 0.5)
			(thermal_bridge_width 0.5)
			(island_removal_mode 0)
		)
		(polygon
			(pts
				(xy 289.231578 -299.116496) (xy 289.231578 -298.672758) (xy 291.556694 -298.672758) (xy 291.556694 -299.116496)
			)
		)
	)
	(zone
		(layer "F.Cu")
		(hatch none 0.5)
		(connect_pads
			(clearance 0)
		)
		(min_thickness 0.25)
		(keepout
			(tracks allowed)
			(vias allowed)
			(pads allowed)
			(copperpour allowed)
			(footprints allowed)
		)
		(placement
			(enabled no)
			(sheetname "")
		)
		(fill
			(thermal_gap 0.5)
			(thermal_bridge_width 0.5)
			(island_removal_mode 0)
		)
		(polygon
			(pts
				(xy 386.24256 -217.668348) (xy 386.52958 -217.668348) (xy 386.56006 -217.637868) (xy 386.56006 -217.010488)
				(xy 386.4737 -216.924128) (xy 386.28574 -216.924128) (xy 386.21208 -216.997788) (xy 386.21208 -217.637868)
			)
		)
	)
	(zone
		(layer "F.Cu")
		(hatch none 0.5)
		(connect_pads
			(clearance 0)
		)
		(min_thickness 0.25)
		(keepout
			(tracks allowed)
			(vias allowed)
			(pads allowed)
			(copperpour allowed)
			(footprints allowed)
		)
		(placement
			(enabled no)
			(sheetname "")
		)
		(fill
			(thermal_gap 0.5)
			(thermal_bridge_width 0.5)
			(island_removal_mode 0)
		)
		(polygon
			(pts
				(xy 307.76291 -299.966634) (xy 307.76291 -299.522896) (xy 310.088026 -299.522896) (xy 310.088026 -299.966634)
			)
		)
	)
	(zone
		(layer "F.Cu")
		(hatch none 0.5)
		(connect_pads
			(clearance 0)
		)
		(min_thickness 0.25)
		(keepout
			(tracks allowed)
			(vias allowed)
			(pads allowed)
			(copperpour allowed)
			(footprints allowed)
		)
		(placement
			(enabled no)
			(sheetname "")
		)
		(fill
			(thermal_gap 0.5)
			(thermal_bridge_width 0.5)
			(island_removal_mode 0)
		)
		(polygon
			(pts
				(xy 180.423058 -250.554998) (xy 180.423058 -250.326398) (xy 182.455058 -250.326398) (xy 182.455058 -250.554998)
			)
		)
	)
	(zone
		(layer "F.Cu")
		(hatch none 0.5)
		(connect_pads
			(clearance 0)
		)
		(min_thickness 0.25)
		(keepout
			(tracks allowed)
			(vias allowed)
			(pads allowed)
			(copperpour allowed)
			(footprints allowed)
		)
		(placement
			(enabled no)
			(sheetname "")
		)
		(fill
			(thermal_gap 0.5)
			(thermal_bridge_width 0.5)
			(island_removal_mode 0)
		)
		(polygon
			(pts
				(xy 440.006994 -315.776356) (xy 442.038994 -315.776356) (xy 442.038994 -316.004956) (xy 440.006994 -316.004956)
				(xy 439.87085 -316.004956) (xy 439.82386 -316.004956) (xy 439.82386 -315.776356) (xy 439.87085 -315.776356)
			)
		)
	)
	(zone
		(layer "F.Cu")
		(hatch none 0.5)
		(connect_pads
			(clearance 0)
		)
		(min_thickness 0.25)
		(keepout
			(tracks allowed)
			(vias allowed)
			(pads allowed)
			(copperpour allowed)
			(footprints allowed)
		)
		(placement
			(enabled no)
			(sheetname "")
		)
		(fill
			(thermal_gap 0.5)
			(thermal_bridge_width 0.5)
			(island_removal_mode 0)
		)
		(polygon
			(pts
				(xy 420.819326 -269.254986) (xy 420.819326 -269.026386) (xy 422.851326 -269.026386) (xy 422.851326 -269.254986)
			)
		)
	)
	(zone
		(layer "F.Cu")
		(hatch none 0.5)
		(connect_pads
			(clearance 0)
		)
		(min_thickness 0.25)
		(keepout
			(tracks allowed)
			(vias allowed)
			(pads allowed)
			(copperpour allowed)
			(footprints allowed)
		)
		(placement
			(enabled no)
			(sheetname "")
		)
		(fill
			(thermal_gap 0.5)
			(thermal_bridge_width 0.5)
			(island_removal_mode 0)
		)
		(polygon
			(pts
				(xy 458.538326 -224.204784) (xy 458.538326 -223.976184) (xy 460.570326 -223.976184) (xy 460.570326 -224.204784)
			)
		)
	)
	(zone
		(layer "F.Cu")
		(hatch none 0.5)
		(connect_pads
			(clearance 0)
		)
		(min_thickness 0.25)
		(keepout
			(tracks allowed)
			(vias allowed)
			(pads allowed)
			(copperpour allowed)
			(footprints allowed)
		)
		(placement
			(enabled no)
			(sheetname "")
		)
		(fill
			(thermal_gap 0.5)
			(thermal_bridge_width 0.5)
			(island_removal_mode 0)
		)
		(polygon
			(pts
				(xy 424.919394 -280.076402) (xy 426.951394 -280.076402) (xy 426.951394 -280.305002) (xy 424.919394 -280.305002)
				(xy 424.78325 -280.305002) (xy 424.73626 -280.305002) (xy 424.73626 -280.076402) (xy 424.78325 -280.076402)
			)
		)
	)
	(zone
		(layer "F.Cu")
		(hatch none 0.5)
		(connect_pads
			(clearance 0)
		)
		(min_thickness 0.25)
		(keepout
			(tracks allowed)
			(vias allowed)
			(pads allowed)
			(copperpour allowed)
			(footprints allowed)
		)
		(placement
			(enabled no)
			(sheetname "")
		)
		(fill
			(thermal_gap 0.5)
			(thermal_bridge_width 0.5)
			(island_removal_mode 0)
		)
		(polygon
			(pts
				(xy 274.143978 -300.816518) (xy 274.143978 -300.37278) (xy 276.469094 -300.37278) (xy 276.469094 -300.816518)
			)
		)
	)
	(zone
		(layer "F.Cu")
		(hatch none 0.5)
		(connect_pads
			(clearance 0)
		)
		(min_thickness 0.25)
		(keepout
			(tracks allowed)
			(vias allowed)
			(pads allowed)
			(copperpour allowed)
			(footprints allowed)
		)
		(placement
			(enabled no)
			(sheetname "")
		)
		(fill
			(thermal_gap 0.5)
			(thermal_bridge_width 0.5)
			(island_removal_mode 0)
		)
		(polygon
			(pts
				(xy 180.423058 -282.005024) (xy 180.423058 -281.776424) (xy 182.455058 -281.776424) (xy 182.455058 -282.005024)
			)
		)
	)
	(zone
		(layer "F.Cu")
		(hatch none 0.5)
		(connect_pads
			(clearance 0)
		)
		(min_thickness 0.25)
		(keepout
			(tracks allowed)
			(vias allowed)
			(pads allowed)
			(copperpour allowed)
			(footprints allowed)
		)
		(placement
			(enabled no)
			(sheetname "")
		)
		(fill
			(thermal_gap 0.5)
			(thermal_bridge_width 0.5)
			(island_removal_mode 0)
		)
		(polygon
			(pts
				(xy 443.450726 -280.305002) (xy 443.450726 -280.076402) (xy 445.482726 -280.076402) (xy 445.482726 -280.305002)
			)
		)
	)
	(zone
		(layer "F.Cu")
		(hatch none 0.5)
		(connect_pads
			(clearance 0)
		)
		(min_thickness 0.25)
		(keepout
			(tracks allowed)
			(vias allowed)
			(pads allowed)
			(copperpour allowed)
			(footprints allowed)
		)
		(placement
			(enabled no)
			(sheetname "")
		)
		(fill
			(thermal_gap 0.5)
			(thermal_bridge_width 0.5)
			(island_removal_mode 0)
		)
		(polygon
			(pts
				(xy 307.76291 -261.71652) (xy 307.76291 -261.272782) (xy 310.088026 -261.272782) (xy 310.088026 -261.71652)
			)
		)
	)
	(zone
		(layer "F.Cu")
		(hatch none 0.5)
		(connect_pads
			(clearance 0)
		)
		(min_thickness 0.25)
		(keepout
			(tracks allowed)
			(vias allowed)
			(pads allowed)
			(copperpour allowed)
			(footprints allowed)
		)
		(placement
			(enabled no)
			(sheetname "")
		)
		(fill
			(thermal_gap 0.5)
			(thermal_bridge_width 0.5)
			(island_removal_mode 0)
		)
		(polygon
			(pts
				(xy 195.510658 -248.854976) (xy 195.510658 -248.626376) (xy 197.542658 -248.626376) (xy 197.542658 -248.854976)
			)
		)
	)
	(zone
		(layer "F.Cu")
		(hatch none 0.5)
		(connect_pads
			(clearance 0)
		)
		(min_thickness 0.25)
		(keepout
			(tracks allowed)
			(vias allowed)
			(pads allowed)
			(copperpour allowed)
			(footprints not_allowed)
		)
		(placement
			(enabled no)
			(sheetname "")
		)
		(fill
			(thermal_gap 0.5)
			(thermal_bridge_width 0.5)
			(island_removal_mode 0)
		)
		(polygon
			(pts
				(xy 418.424614 -446.989962) (xy 418.424614 -438.989978) (xy 429.424592 -438.989978) (xy 429.424592 -446.989962)
			)
		)
	)
	(zone
		(layer "F.Cu")
		(hatch none 0.5)
		(connect_pads
			(clearance 0)
		)
		(min_thickness 0.25)
		(keepout
			(tracks allowed)
			(vias allowed)
			(pads allowed)
			(copperpour allowed)
			(footprints allowed)
		)
		(placement
			(enabled no)
			(sheetname "")
		)
		(fill
			(thermal_gap 0.5)
			(thermal_bridge_width 0.5)
			(island_removal_mode 0)
		)
		(polygon
			(pts
				(xy 157.791658 -297.304968) (xy 157.791658 -297.076368) (xy 159.823658 -297.076368) (xy 159.823658 -297.304968)
			)
		)
	)
	(zone
		(layer "F.Cu")
		(hatch none 0.5)
		(connect_pads
			(clearance 0)
		)
		(min_thickness 0.25)
		(keepout
			(tracks allowed)
			(vias allowed)
			(pads allowed)
			(copperpour allowed)
			(footprints allowed)
		)
		(placement
			(enabled no)
			(sheetname "")
		)
		(fill
			(thermal_gap 0.5)
			(thermal_bridge_width 0.5)
			(island_removal_mode 0)
		)
		(polygon
			(pts
				(xy 41.29151 -267.66647) (xy 41.29151 -267.222732) (xy 43.616626 -267.222732) (xy 43.616626 -267.66647)
			)
		)
	)
	(zone
		(layer "F.Cu")
		(hatch none 0.5)
		(connect_pads
			(clearance 0)
		)
		(min_thickness 0.25)
		(keepout
			(tracks allowed)
			(vias allowed)
			(pads allowed)
			(copperpour allowed)
			(footprints allowed)
		)
		(placement
			(enabled no)
			(sheetname "")
		)
		(fill
			(thermal_gap 0.5)
			(thermal_bridge_width 0.5)
			(island_removal_mode 0)
		)
		(polygon
			(pts
				(xy 192.066926 -219.107004) (xy 194.098926 -219.107004) (xy 194.098926 -218.878404) (xy 192.066926 -218.878404)
				(xy 191.935608 -218.878404) (xy 191.9097 -218.878404) (xy 191.9097 -219.107004) (xy 191.935608 -219.107004)
			)
		)
	)
	(zone
		(layer "F.Cu")
		(hatch none 0.5)
		(connect_pads
			(clearance 0)
		)
		(min_thickness 0.25)
		(keepout
			(tracks allowed)
			(vias allowed)
			(pads allowed)
			(copperpour allowed)
			(footprints allowed)
		)
		(placement
			(enabled no)
			(sheetname "")
		)
		(fill
			(thermal_gap 0.5)
			(thermal_bridge_width 0.5)
			(island_removal_mode 0)
		)
		(polygon
			(pts
				(xy 392.369548 -20.04822) (xy 392.369548 -16.913606) (xy 394.14831 -16.913606) (xy 394.14831 -20.04822)
			)
		)
	)
	(zone
		(layer "F.Cu")
		(hatch none 0.5)
		(connect_pads
			(clearance 0)
		)
		(min_thickness 0.25)
		(keepout
			(tracks allowed)
			(vias allowed)
			(pads allowed)
			(copperpour allowed)
			(footprints allowed)
		)
		(placement
			(enabled no)
			(sheetname "")
		)
		(fill
			(thermal_gap 0.5)
			(thermal_bridge_width 0.5)
			(island_removal_mode 0)
		)
		(polygon
			(pts
				(xy 26.053288 -319.243456) (xy 26.053288 -316.881256) (xy 28.669488 -316.881256) (xy 28.669488 -319.243456)
			)
		)
	)
	(zone
		(layer "F.Cu")
		(hatch none 0.5)
		(connect_pads
			(clearance 0)
		)
		(min_thickness 0.25)
		(keepout
			(tracks allowed)
			(vias allowed)
			(pads allowed)
			(copperpour allowed)
			(footprints allowed)
		)
		(placement
			(enabled no)
			(sheetname "")
		)
		(fill
			(thermal_gap 0.5)
			(thermal_bridge_width 0.5)
			(island_removal_mode 0)
		)
		(polygon
			(pts
				(xy 179.61356 -343.080848) (xy 179.61356 -339.882988) (xy 183.77662 -339.882988) (xy 183.77662 -343.080848)
			)
		)
	)
	(zone
		(layer "F.Cu")
		(hatch none 0.5)
		(connect_pads
			(clearance 0)
		)
		(min_thickness 0.25)
		(keepout
			(tracks allowed)
			(vias allowed)
			(pads allowed)
			(copperpour allowed)
			(footprints allowed)
		)
		(placement
			(enabled no)
			(sheetname "")
		)
		(fill
			(thermal_gap 0.5)
			(thermal_bridge_width 0.5)
			(island_removal_mode 0)
		)
		(polygon
			(pts
				(xy 304.319178 -295.716452) (xy 304.319178 -295.272714) (xy 306.644294 -295.272714) (xy 306.644294 -295.716452)
			)
		)
	)
	(zone
		(layer "F.Cu")
		(hatch none 0.5)
		(connect_pads
			(clearance 0)
		)
		(min_thickness 0.25)
		(keepout
			(tracks allowed)
			(vias allowed)
			(pads allowed)
			(copperpour allowed)
			(footprints allowed)
		)
		(placement
			(enabled no)
			(sheetname "")
		)
		(fill
			(thermal_gap 0.5)
			(thermal_bridge_width 0.5)
			(island_removal_mode 0)
		)
		(polygon
			(pts
				(xy 277.58771 -214.96655) (xy 277.58771 -214.522812) (xy 279.912826 -214.522812) (xy 279.912826 -214.96655)
			)
		)
	)
	(zone
		(layer "F.Cu")
		(hatch none 0.5)
		(connect_pads
			(clearance 0)
		)
		(min_thickness 0.25)
		(keepout
			(tracks allowed)
			(vias allowed)
			(pads allowed)
			(copperpour allowed)
			(footprints allowed)
		)
		(placement
			(enabled no)
			(sheetname "")
		)
		(fill
			(thermal_gap 0.5)
			(thermal_bridge_width 0.5)
			(island_removal_mode 0)
		)
		(polygon
			(pts
				(xy 84.140802 -222.874586) (xy 84.343748 -223.077532) (xy 84.386928 -223.077532) (xy 84.830666 -222.633794)
				(xy 84.830666 -222.51162) (xy 84.69757 -222.378778) (xy 84.59343 -222.378778) (xy 84.140802 -222.831406)
			)
		)
	)
	(zone
		(layer "F.Cu")
		(hatch none 0.5)
		(connect_pads
			(clearance 0)
		)
		(min_thickness 0.25)
		(keepout
			(tracks allowed)
			(vias allowed)
			(pads allowed)
			(copperpour allowed)
			(footprints allowed)
		)
		(placement
			(enabled no)
			(sheetname "")
		)
		(fill
			(thermal_gap 0.5)
			(thermal_bridge_width 0.5)
			(island_removal_mode 0)
		)
		(polygon
			(pts
				(xy 405.731726 -273.504914) (xy 405.731726 -273.276314) (xy 407.763726 -273.276314) (xy 407.763726 -273.504914)
			)
		)
	)
	(zone
		(layer "F.Cu")
		(hatch none 0.5)
		(connect_pads
			(clearance 0)
		)
		(min_thickness 0.25)
		(keepout
			(tracks allowed)
			(vias allowed)
			(pads allowed)
			(copperpour allowed)
			(footprints allowed)
		)
		(placement
			(enabled no)
			(sheetname "")
		)
		(fill
			(thermal_gap 0.5)
			(thermal_bridge_width 0.5)
			(island_removal_mode 0)
		)
		(polygon
			(pts
				(xy 192.066926 -303.876202) (xy 194.098926 -303.876202) (xy 194.098926 -304.104802) (xy 192.066926 -304.104802)
				(xy 191.935608 -304.104802) (xy 191.9097 -304.104802) (xy 191.9097 -303.876202) (xy 191.935608 -303.876202)
			)
		)
	)
	(zone
		(layer "F.Cu")
		(hatch none 0.5)
		(connect_pads
			(clearance 0)
		)
		(min_thickness 0.25)
		(keepout
			(tracks not_allowed)
			(vias allowed)
			(pads allowed)
			(copperpour not_allowed)
			(footprints allowed)
		)
		(placement
			(enabled no)
			(sheetname "")
		)
		(fill
			(thermal_gap 0.5)
			(thermal_bridge_width 0.5)
			(island_removal_mode 0)
		)
		(polygon
			(pts
				(xy 64.268858 -11.992356) (xy 64.444118 -11.992356) (xy 64.472058 -11.964416) (xy 64.472058 -10.569956)
				(xy 64.449198 -10.547096) (xy 64.279018 -10.547096) (xy 64.258698 -10.567416) (xy 64.258698 -11.982196)
			)
		)
	)
	(zone
		(layer "F.Cu")
		(hatch none 0.5)
		(connect_pads
			(clearance 0)
		)
		(min_thickness 0.25)
		(keepout
			(tracks allowed)
			(vias allowed)
			(pads allowed)
			(copperpour allowed)
			(footprints allowed)
		)
		(placement
			(enabled no)
			(sheetname "")
		)
		(fill
			(thermal_gap 0.5)
			(thermal_bridge_width 0.5)
			(island_removal_mode 0)
		)
		(polygon
			(pts
				(xy 184.265062 -319.243202) (xy 184.265062 -316.881002) (xy 186.881262 -316.881002) (xy 186.881262 -319.243202)
			)
		)
	)
	(zone
		(layer "F.Cu")
		(hatch none 0.5)
		(connect_pads
			(clearance 0)
		)
		(min_thickness 0.25)
		(keepout
			(tracks allowed)
			(vias allowed)
			(pads allowed)
			(copperpour allowed)
			(footprints allowed)
		)
		(placement
			(enabled no)
			(sheetname "")
		)
		(fill
			(thermal_gap 0.5)
			(thermal_bridge_width 0.5)
			(island_removal_mode 0)
		)
		(polygon
			(pts
				(xy 207.154526 -264.776204) (xy 209.186526 -264.776204) (xy 209.186526 -265.004804) (xy 207.154526 -265.004804)
				(xy 206.987902 -265.004804) (xy 206.987902 -264.776204)
			)
		)
	)
	(zone
		(layer "F.Cu")
		(hatch none 0.5)
		(connect_pads
			(clearance 0)
		)
		(min_thickness 0.25)
		(keepout
			(tracks allowed)
			(vias allowed)
			(pads allowed)
			(copperpour allowed)
			(footprints allowed)
		)
		(placement
			(enabled no)
			(sheetname "")
		)
		(fill
			(thermal_gap 0.5)
			(thermal_bridge_width 0.5)
			(island_removal_mode 0)
		)
		(polygon
			(pts
				(xy 210.598258 -311.755028) (xy 210.598258 -311.526428) (xy 212.630258 -311.526428) (xy 212.630258 -311.755028)
			)
		)
	)
	(zone
		(layer "F.Cu")
		(hatch none 0.5)
		(connect_pads
			(clearance 0)
		)
		(min_thickness 0.25)
		(keepout
			(tracks allowed)
			(vias allowed)
			(pads allowed)
			(copperpour allowed)
			(footprints not_allowed)
		)
		(placement
			(enabled no)
			(sheetname "")
		)
		(fill
			(thermal_gap 0.5)
			(thermal_bridge_width 0.5)
			(island_removal_mode 0)
		)
		(polygon
			(pts
				(xy 187.988702 -330.091796) (xy 194.088512 -330.091796) (xy 194.088512 -186.09183) (xy 187.988702 -186.09183)
			)
		)
	)
	(zone
		(layer "F.Cu")
		(hatch none 0.5)
		(connect_pads
			(clearance 0)
		)
		(min_thickness 0.25)
		(keepout
			(tracks allowed)
			(vias allowed)
			(pads allowed)
			(copperpour allowed)
			(footprints allowed)
		)
		(placement
			(enabled no)
			(sheetname "")
		)
		(fill
			(thermal_gap 0.5)
			(thermal_bridge_width 0.5)
			(island_removal_mode 0)
		)
		(polygon
			(pts
				(xy 401.598384 -404.802594) (xy 401.598384 -399.959576) (xy 403.48281 -399.959576) (xy 403.48281 -404.802594)
			)
		)
	)
	(zone
		(layer "F.Cu")
		(hatch none 0.5)
		(connect_pads
			(clearance 0)
		)
		(min_thickness 0.25)
		(keepout
			(tracks allowed)
			(vias allowed)
			(pads allowed)
			(copperpour allowed)
			(footprints allowed)
		)
		(placement
			(enabled no)
			(sheetname "")
		)
		(fill
			(thermal_gap 0.5)
			(thermal_bridge_width 0.5)
			(island_removal_mode 0)
		)
		(polygon
			(pts
				(xy 440.006994 -225.67646) (xy 442.038994 -225.67646) (xy 442.038994 -225.90506) (xy 440.006994 -225.90506)
				(xy 439.87085 -225.90506) (xy 439.82386 -225.90506) (xy 439.82386 -225.67646) (xy 439.87085 -225.67646)
			)
		)
	)
	(zone
		(layer "F.Cu")
		(hatch none 0.5)
		(connect_pads
			(clearance 0)
		)
		(min_thickness 0.25)
		(keepout
			(tracks allowed)
			(vias allowed)
			(pads allowed)
			(copperpour allowed)
			(footprints allowed)
		)
		(placement
			(enabled no)
			(sheetname "")
		)
		(fill
			(thermal_gap 0.5)
			(thermal_bridge_width 0.5)
			(island_removal_mode 0)
		)
		(polygon
			(pts
				(xy 41.291764 -238.76635) (xy 41.291764 -238.322612) (xy 43.61688 -238.322612) (xy 43.61688 -238.76635)
			)
		)
	)
	(zone
		(layer "F.Cu")
		(hatch none 0.5)
		(connect_pads
			(clearance 0)
		)
		(min_thickness 0.25)
		(keepout
			(tracks allowed)
			(vias allowed)
			(pads allowed)
			(copperpour allowed)
			(footprints allowed)
		)
		(placement
			(enabled no)
			(sheetname "")
		)
		(fill
			(thermal_gap 0.5)
			(thermal_bridge_width 0.5)
			(island_removal_mode 0)
		)
		(polygon
			(pts
				(xy 443.450726 -202.105006) (xy 443.450726 -201.876406) (xy 445.482726 -201.876406) (xy 445.482726 -202.105006)
			)
		)
	)
	(zone
		(layer "F.Cu")
		(hatch none 0.5)
		(connect_pads
			(clearance 0)
		)
		(min_thickness 0.25)
		(keepout
			(tracks allowed)
			(vias allowed)
			(pads allowed)
			(copperpour allowed)
			(footprints allowed)
		)
		(placement
			(enabled no)
			(sheetname "")
		)
		(fill
			(thermal_gap 0.5)
			(thermal_bridge_width 0.5)
			(island_removal_mode 0)
		)
		(polygon
			(pts
				(xy 289.231578 -241.31651) (xy 289.231578 -240.872772) (xy 291.556694 -240.872772) (xy 291.556694 -241.31651)
			)
		)
	)
	(zone
		(layer "F.Cu")
		(hatch none 0.5)
		(connect_pads
			(clearance 0)
		)
		(min_thickness 0.25)
		(keepout
			(tracks allowed)
			(vias allowed)
			(pads allowed)
			(copperpour allowed)
			(footprints allowed)
		)
		(placement
			(enabled no)
			(sheetname "")
		)
		(fill
			(thermal_gap 0.5)
			(thermal_bridge_width 0.5)
			(island_removal_mode 0)
		)
		(polygon
			(pts
				(xy 413.275526 -244.376194) (xy 415.307526 -244.376194) (xy 415.307526 -244.604794) (xy 413.275526 -244.604794)
				(xy 413.081724 -244.604794) (xy 413.081724 -244.376194)
			)
		)
	)
	(zone
		(layer "F.Cu")
		(hatch none 0.5)
		(connect_pads
			(clearance 0)
		)
		(min_thickness 0.25)
		(keepout
			(tracks allowed)
			(vias allowed)
			(pads allowed)
			(copperpour allowed)
			(footprints not_allowed)
		)
		(placement
			(enabled no)
			(sheetname "")
		)
		(fill
			(thermal_gap 0.5)
			(thermal_bridge_width 0.5)
			(island_removal_mode 0)
		)
		(polygon
			(pts
				(arc
					(start 260.124956 -360.764074)
					(mid 258.12496 -362.76407)
					(end 256.124964 -360.764074)
				)
				(arc
					(start 256.124964 -360.764074)
					(mid 258.12496 -358.764078)
					(end 260.124956 -360.764074)
				)
			)
		)
	)
	(zone
		(layer "F.Cu")
		(hatch none 0.5)
		(connect_pads
			(clearance 0)
		)
		(min_thickness 0.25)
		(keepout
			(tracks allowed)
			(vias allowed)
			(pads allowed)
			(copperpour allowed)
			(footprints allowed)
		)
		(placement
			(enabled no)
			(sheetname "")
		)
		(fill
			(thermal_gap 0.5)
			(thermal_bridge_width 0.5)
			(island_removal_mode 0)
		)
		(polygon
			(pts
				(xy 185.30316 -401.91944) (xy 185.30316 -400.04238) (xy 189.39002 -400.04238) (xy 189.39002 -401.91944)
			)
		)
	)
	(zone
		(layer "F.Cu")
		(hatch none 0.5)
		(connect_pads
			(clearance 0)
		)
		(min_thickness 0.25)
		(keepout
			(tracks allowed)
			(vias allowed)
			(pads allowed)
			(copperpour allowed)
			(footprints allowed)
		)
		(placement
			(enabled no)
			(sheetname "")
		)
		(fill
			(thermal_gap 0.5)
			(thermal_bridge_width 0.5)
			(island_removal_mode 0)
		)
		(polygon
			(pts
				(xy 289.231578 -284.666436) (xy 289.231578 -284.222698) (xy 291.556694 -284.222698) (xy 291.556694 -284.666436)
			)
		)
	)
	(zone
		(layer "F.Cu")
		(hatch none 0.5)
		(connect_pads
			(clearance 0)
		)
		(min_thickness 0.25)
		(keepout
			(tracks allowed)
			(vias allowed)
			(pads allowed)
			(copperpour allowed)
			(footprints allowed)
		)
		(placement
			(enabled no)
			(sheetname "")
		)
		(fill
			(thermal_gap 0.5)
			(thermal_bridge_width 0.5)
			(island_removal_mode 0)
		)
		(polygon
			(pts
				(xy 41.29151 -308.46649) (xy 41.29151 -308.022752) (xy 43.616626 -308.022752) (xy 43.616626 -308.46649)
			)
		)
	)
	(zone
		(layer "F.Cu")
		(hatch none 0.5)
		(connect_pads
			(clearance 0)
		)
		(min_thickness 0.25)
		(keepout
			(tracks allowed)
			(vias allowed)
			(pads allowed)
			(copperpour allowed)
			(footprints allowed)
		)
		(placement
			(enabled no)
			(sheetname "")
		)
		(fill
			(thermal_gap 0.5)
			(thermal_bridge_width 0.5)
			(island_removal_mode 0)
		)
		(polygon
			(pts
				(xy 292.67531 -206.46644) (xy 292.67531 -206.022702) (xy 295.000426 -206.022702) (xy 295.000426 -206.46644)
			)
		)
	)
	(zone
		(layer "F.Cu")
		(hatch none 0.5)
		(connect_pads
			(clearance 0)
		)
		(min_thickness 0.25)
		(keepout
			(tracks allowed)
			(vias allowed)
			(pads allowed)
			(copperpour allowed)
			(footprints not_allowed)
		)
		(placement
			(enabled no)
			(sheetname "")
		)
		(fill
			(thermal_gap 0.5)
			(thermal_bridge_width 0.5)
			(island_removal_mode 0)
		)
		(polygon
			(pts
				(arc
					(start 4.19989 -22.29993)
					(mid 6.999986 -19.499834)
					(end 9.800082 -22.29993)
				)
				(arc
					(start 9.800082 -22.29993)
					(mid 6.999986 -25.100026)
					(end 4.19989 -22.29993)
				)
			)
		)
	)
	(zone
		(layer "F.Cu")
		(hatch none 0.5)
		(connect_pads
			(clearance 0)
		)
		(min_thickness 0.25)
		(keepout
			(tracks allowed)
			(vias allowed)
			(pads allowed)
			(copperpour allowed)
			(footprints allowed)
		)
		(placement
			(enabled no)
			(sheetname "")
		)
		(fill
			(thermal_gap 0.5)
			(thermal_bridge_width 0.5)
			(island_removal_mode 0)
		)
		(polygon
			(pts
				(xy 155.37434 -43.366182) (xy 155.37434 -42.49801) (xy 157.342332 -42.49801) (xy 157.342332 -43.366182)
			)
		)
	)
	(zone
		(layer "F.Cu")
		(hatch none 0.5)
		(connect_pads
			(clearance 0)
		)
		(min_thickness 0.25)
		(keepout
			(tracks allowed)
			(vias allowed)
			(pads allowed)
			(copperpour allowed)
			(footprints allowed)
		)
		(placement
			(enabled no)
			(sheetname "")
		)
		(fill
			(thermal_gap 0.5)
			(thermal_bridge_width 0.5)
			(island_removal_mode 0)
		)
		(polygon
			(pts
				(xy 180.423058 -236.104938) (xy 180.423058 -235.876338) (xy 182.455058 -235.876338) (xy 182.455058 -236.104938)
			)
		)
	)
	(zone
		(layer "F.Cu")
		(hatch none 0.5)
		(connect_pads
			(clearance 0)
		)
		(min_thickness 0.25)
		(keepout
			(tracks allowed)
			(vias allowed)
			(pads allowed)
			(copperpour allowed)
			(footprints allowed)
		)
		(placement
			(enabled no)
			(sheetname "")
		)
		(fill
			(thermal_gap 0.5)
			(thermal_bridge_width 0.5)
			(island_removal_mode 0)
		)
		(polygon
			(pts
				(xy 440.006994 -268.404848) (xy 440.006994 -268.176248) (xy 442.038994 -268.176248) (xy 442.038994 -268.404848)
			)
		)
	)
	(zone
		(layer "F.Cu")
		(hatch none 0.5)
		(connect_pads
			(clearance 0)
		)
		(min_thickness 0.25)
		(keepout
			(tracks allowed)
			(vias allowed)
			(pads allowed)
			(copperpour allowed)
			(footprints allowed)
		)
		(placement
			(enabled no)
			(sheetname "")
		)
		(fill
			(thermal_gap 0.5)
			(thermal_bridge_width 0.5)
			(island_removal_mode 0)
		)
		(polygon
			(pts
				(xy 383.93624 -286.598868) (xy 384.22326 -286.598868) (xy 384.25374 -286.568388) (xy 384.25374 -285.941008)
				(xy 384.16738 -285.854648) (xy 383.97942 -285.854648) (xy 383.90576 -285.928308) (xy 383.90576 -286.568388)
			)
		)
	)
	(zone
		(layer "F.Cu")
		(hatch none 0.5)
		(connect_pads
			(clearance 0)
		)
		(min_thickness 0.25)
		(keepout
			(tracks allowed)
			(vias allowed)
			(pads allowed)
			(copperpour allowed)
			(footprints allowed)
		)
		(placement
			(enabled no)
			(sheetname "")
		)
		(fill
			(thermal_gap 0.5)
			(thermal_bridge_width 0.5)
			(island_removal_mode 0)
		)
		(polygon
			(pts
				(xy 292.67531 -299.116496) (xy 292.67531 -298.672758) (xy 295.000426 -298.672758) (xy 295.000426 -299.116496)
			)
		)
	)
	(zone
		(layer "F.Cu")
		(hatch none 0.5)
		(connect_pads
			(clearance 0)
		)
		(min_thickness 0.25)
		(keepout
			(tracks allowed)
			(vias allowed)
			(pads allowed)
			(copperpour allowed)
			(footprints allowed)
		)
		(placement
			(enabled no)
			(sheetname "")
		)
		(fill
			(thermal_gap 0.5)
			(thermal_bridge_width 0.5)
			(island_removal_mode 0)
		)
		(polygon
			(pts
				(xy 63.900812 -197.966584) (xy 63.900812 -197.522846) (xy 66.237612 -197.522846) (xy 66.237612 -197.966584)
			)
		)
	)
	(zone
		(layer "F.Cu")
		(hatch none 0.5)
		(connect_pads
			(clearance 0)
		)
		(min_thickness 0.25)
		(keepout
			(tracks allowed)
			(vias allowed)
			(pads allowed)
			(copperpour allowed)
			(footprints allowed)
		)
		(placement
			(enabled no)
			(sheetname "")
		)
		(fill
			(thermal_gap 0.5)
			(thermal_bridge_width 0.5)
			(island_removal_mode 0)
		)
		(polygon
			(pts
				(xy 307.76291 -268.516608) (xy 307.76291 -268.07287) (xy 310.03748 -268.07287) (xy 310.03748 -268.516608)
			)
		)
	)
	(zone
		(layer "F.Cu")
		(hatch none 0.5)
		(connect_pads
			(clearance 0)
		)
		(min_thickness 0.25)
		(keepout
			(tracks allowed)
			(vias allowed)
			(pads allowed)
			(copperpour allowed)
			(footprints allowed)
		)
		(placement
			(enabled no)
			(sheetname "")
		)
		(fill
			(thermal_gap 0.5)
			(thermal_bridge_width 0.5)
			(island_removal_mode 0)
		)
		(polygon
			(pts
				(xy 157.791658 -203.805028) (xy 157.791658 -203.576428) (xy 159.823658 -203.576428) (xy 159.823658 -203.805028)
			)
		)
	)
	(zone
		(layer "F.Cu")
		(hatch none 0.5)
		(connect_pads
			(clearance 0)
		)
		(min_thickness 0.25)
		(keepout
			(tracks allowed)
			(vias allowed)
			(pads allowed)
			(copperpour allowed)
			(footprints allowed)
		)
		(placement
			(enabled no)
			(sheetname "")
		)
		(fill
			(thermal_gap 0.5)
			(thermal_bridge_width 0.5)
			(island_removal_mode 0)
		)
		(polygon
			(pts
				(xy 56.37911 -268.922754) (xy 58.704226 -268.922754) (xy 58.704226 -269.366492) (xy 58.704226 -269.821914)
				(xy 56.22163 -269.821914) (xy 56.22163 -268.922754)
			)
		)
	)
	(zone
		(layer "F.Cu")
		(hatch none 0.5)
		(connect_pads
			(clearance 0)
		)
		(min_thickness 0.25)
		(keepout
			(tracks allowed)
			(vias allowed)
			(pads allowed)
			(copperpour allowed)
			(footprints allowed)
		)
		(placement
			(enabled no)
			(sheetname "")
		)
		(fill
			(thermal_gap 0.5)
			(thermal_bridge_width 0.5)
			(island_removal_mode 0)
		)
		(polygon
			(pts
				(xy 56.926226 -153.945082) (xy 52.920646 -153.945082) (xy 52.440586 -154.425142) (xy 52.440586 -156.490162)
				(xy 52.712366 -156.761942) (xy 54.566566 -156.761942) (xy 54.818026 -157.013402) (xy 54.818026 -158.933642)
				(xy 55.234586 -159.350202) (xy 56.725566 -159.350202) (xy 57.373266 -158.702502) (xy 57.373266 -154.392122)
			)
		)
	)
	(zone
		(layer "F.Cu")
		(hatch none 0.5)
		(connect_pads
			(clearance 0)
		)
		(min_thickness 0.25)
		(keepout
			(tracks allowed)
			(vias allowed)
			(pads allowed)
			(copperpour allowed)
			(footprints allowed)
		)
		(placement
			(enabled no)
			(sheetname "")
		)
		(fill
			(thermal_gap 0.5)
			(thermal_bridge_width 0.5)
			(island_removal_mode 0)
		)
		(polygon
			(pts
				(xy 455.094594 -276.676358) (xy 457.126594 -276.676358) (xy 457.126594 -276.904958) (xy 455.094594 -276.904958)
				(xy 454.95845 -276.904958) (xy 454.91146 -276.904958) (xy 454.91146 -276.676358) (xy 454.95845 -276.676358)
			)
		)
	)
	(zone
		(layer "F.Cu")
		(hatch none 0.5)
		(connect_pads
			(clearance 0)
		)
		(min_thickness 0.25)
		(keepout
			(tracks allowed)
			(vias allowed)
			(pads allowed)
			(copperpour allowed)
			(footprints allowed)
		)
		(placement
			(enabled no)
			(sheetname "")
		)
		(fill
			(thermal_gap 0.5)
			(thermal_bridge_width 0.5)
			(island_removal_mode 0)
		)
		(polygon
			(pts
				(xy 455.094594 -308.126384) (xy 457.126594 -308.126384) (xy 457.126594 -308.354984) (xy 455.094594 -308.354984)
				(xy 454.95845 -308.354984) (xy 454.91146 -308.354984) (xy 454.91146 -308.126384) (xy 454.95845 -308.126384)
			)
		)
	)
	(zone
		(layer "F.Cu")
		(hatch none 0.5)
		(connect_pads
			(clearance 0)
		)
		(min_thickness 0.25)
		(keepout
			(tracks allowed)
			(vias allowed)
			(pads allowed)
			(copperpour allowed)
			(footprints allowed)
		)
		(placement
			(enabled no)
			(sheetname "")
		)
		(fill
			(thermal_gap 0.5)
			(thermal_bridge_width 0.5)
			(island_removal_mode 0)
		)
		(polygon
			(pts
				(xy 405.788622 -242.676426) (xy 407.719022 -242.676426) (xy 407.719022 -242.905026) (xy 405.788622 -242.905026)
				(xy 405.52497 -242.905026) (xy 405.52497 -242.676426)
			)
		)
	)
	(zone
		(layer "F.Cu")
		(hatch none 0.5)
		(connect_pads
			(clearance 0)
		)
		(min_thickness 0.25)
		(keepout
			(tracks allowed)
			(vias allowed)
			(pads allowed)
			(copperpour allowed)
			(footprints allowed)
		)
		(placement
			(enabled no)
			(sheetname "")
		)
		(fill
			(thermal_gap 0.5)
			(thermal_bridge_width 0.5)
			(island_removal_mode 0)
		)
		(polygon
			(pts
				(xy 423.315892 -360.061002) (xy 423.315892 -364.066582) (xy 423.795952 -364.546642) (xy 425.860972 -364.546642)
				(xy 426.132752 -364.274862) (xy 426.132752 -362.420662) (xy 426.384212 -362.169202) (xy 428.304452 -362.169202)
				(xy 428.721012 -361.752642) (xy 428.721012 -360.261662) (xy 428.073312 -359.613962) (xy 423.762932 -359.613962)
			)
		)
	)
	(zone
		(layer "F.Cu")
		(hatch none 0.5)
		(connect_pads
			(clearance 0)
		)
		(min_thickness 0.25)
		(keepout
			(tracks allowed)
			(vias allowed)
			(pads allowed)
			(copperpour allowed)
			(footprints allowed)
		)
		(placement
			(enabled no)
			(sheetname "")
		)
		(fill
			(thermal_gap 0.5)
			(thermal_bridge_width 0.5)
			(island_removal_mode 0)
		)
		(polygon
			(pts
				(xy 458.538326 -286.254952) (xy 458.538326 -286.026352) (xy 460.570326 -286.026352) (xy 460.570326 -286.254952)
			)
		)
	)
	(zone
		(layer "F.Cu")
		(hatch none 0.5)
		(connect_pads
			(clearance 0)
		)
		(min_thickness 0.25)
		(keepout
			(tracks allowed)
			(vias allowed)
			(pads allowed)
			(copperpour allowed)
			(footprints allowed)
		)
		(placement
			(enabled no)
			(sheetname "")
		)
		(fill
			(thermal_gap 0.5)
			(thermal_bridge_width 0.5)
			(island_removal_mode 0)
		)
		(polygon
			(pts
				(xy 458.538326 -300.705012) (xy 458.538326 -300.476412) (xy 460.570326 -300.476412) (xy 460.570326 -300.705012)
			)
		)
	)
	(zone
		(layer "F.Cu")
		(hatch none 0.5)
		(connect_pads
			(clearance 0)
		)
		(min_thickness 0.25)
		(keepout
			(tracks allowed)
			(vias allowed)
			(pads allowed)
			(copperpour allowed)
			(footprints allowed)
		)
		(placement
			(enabled no)
			(sheetname "")
		)
		(fill
			(thermal_gap 0.5)
			(thermal_bridge_width 0.5)
			(island_removal_mode 0)
		)
		(polygon
			(pts
				(xy 14.560042 -311.01665) (xy 14.560042 -310.572912) (xy 16.885158 -310.572912) (xy 16.885158 -311.01665)
			)
		)
	)
	(zone
		(layer "F.Cu")
		(hatch none 0.5)
		(connect_pads
			(clearance 0)
		)
		(min_thickness 0.25)
		(keepout
			(tracks allowed)
			(vias allowed)
			(pads allowed)
			(copperpour allowed)
			(footprints allowed)
		)
		(placement
			(enabled no)
			(sheetname "")
		)
		(fill
			(thermal_gap 0.5)
			(thermal_bridge_width 0.5)
			(island_removal_mode 0)
		)
		(polygon
			(pts
				(xy 26.20391 -262.566658) (xy 26.20391 -262.12292) (xy 28.529026 -262.12292) (xy 28.529026 -262.566658)
			)
		)
	)
	(zone
		(layer "F.Cu")
		(hatch none 0.5)
		(connect_pads
			(clearance 0)
		)
		(min_thickness 0.25)
		(keepout
			(tracks allowed)
			(vias allowed)
			(pads allowed)
			(copperpour allowed)
			(footprints allowed)
		)
		(placement
			(enabled no)
			(sheetname "")
		)
		(fill
			(thermal_gap 0.5)
			(thermal_bridge_width 0.5)
			(island_removal_mode 0)
		)
		(polygon
			(pts
				(xy 338.564982 -410.948886) (xy 338.564982 -406.105868) (xy 340.449408 -406.105868) (xy 340.449408 -410.948886)
			)
		)
	)
	(zone
		(layer "F.Cu")
		(hatch none 0.5)
		(connect_pads
			(clearance 0)
		)
		(min_thickness 0.25)
		(keepout
			(tracks allowed)
			(vias allowed)
			(pads allowed)
			(copperpour allowed)
			(footprints allowed)
		)
		(placement
			(enabled no)
			(sheetname "")
		)
		(fill
			(thermal_gap 0.5)
			(thermal_bridge_width 0.5)
			(island_removal_mode 0)
		)
		(polygon
			(pts
				(xy 380.217934 -336.996786) (xy 376.682254 -336.996786) (xy 376.682254 -334.913986) (xy 380.217934 -334.913986)
			)
		)
	)
	(zone
		(layer "F.Cu")
		(hatch none 0.5)
		(connect_pads
			(clearance 0)
		)
		(min_thickness 0.25)
		(keepout
			(tracks allowed)
			(vias allowed)
			(pads allowed)
			(copperpour allowed)
			(footprints allowed)
		)
		(placement
			(enabled no)
			(sheetname "")
		)
		(fill
			(thermal_gap 0.5)
			(thermal_bridge_width 0.5)
			(island_removal_mode 0)
		)
		(polygon
			(pts
				(xy 289.231578 -230.266494) (xy 289.231578 -229.822756) (xy 291.556694 -229.822756) (xy 291.556694 -230.266494)
			)
		)
	)
	(zone
		(layer "F.Cu")
		(hatch none 0.5)
		(connect_pads
			(clearance 0)
		)
		(min_thickness 0.25)
		(keepout
			(tracks allowed)
			(vias allowed)
			(pads allowed)
			(copperpour allowed)
			(footprints allowed)
		)
		(placement
			(enabled no)
			(sheetname "")
		)
		(fill
			(thermal_gap 0.5)
			(thermal_bridge_width 0.5)
			(island_removal_mode 0)
		)
		(polygon
			(pts
				(xy 409.831794 -239.276382) (xy 411.863794 -239.276382) (xy 412.057088 -239.276382) (xy 412.057088 -239.504982)
				(xy 412.057088 -240.092992) (xy 409.660598 -240.092992) (xy 409.660598 -239.544098) (xy 409.660598 -239.276382)
			)
		)
	)
	(zone
		(layer "F.Cu")
		(hatch none 0.5)
		(connect_pads
			(clearance 0)
		)
		(min_thickness 0.25)
		(keepout
			(tracks allowed)
			(vias allowed)
			(pads allowed)
			(copperpour allowed)
			(footprints allowed)
		)
		(placement
			(enabled no)
			(sheetname "")
		)
		(fill
			(thermal_gap 0.5)
			(thermal_bridge_width 0.5)
			(island_removal_mode 0)
		)
		(polygon
			(pts
				(xy 56.37911 -251.516642) (xy 56.37911 -251.072904) (xy 58.704226 -251.072904) (xy 58.704226 -251.516642)
			)
		)
	)
	(zone
		(layer "F.Cu")
		(hatch none 0.5)
		(connect_pads
			(clearance 0)
		)
		(min_thickness 0.25)
		(keepout
			(tracks allowed)
			(vias allowed)
			(pads allowed)
			(copperpour allowed)
			(footprints allowed)
		)
		(placement
			(enabled no)
			(sheetname "")
		)
		(fill
			(thermal_gap 0.5)
			(thermal_bridge_width 0.5)
			(island_removal_mode 0)
		)
		(polygon
			(pts
				(xy 389.30453 -234.91317) (xy 388.73303 -234.91317) (xy 388.654036 -234.992164) (xy 388.41553 -234.992418)
				(xy 388.37743 -234.954318) (xy 388.37743 -233.812334) (xy 388.4549 -233.734864) (xy 388.4549 -233.151934)
				(xy 388.740396 -232.866438) (xy 388.740396 -232.725468) (xy 388.175246 -232.160318) (xy 388.175246 -232.108756)
				(xy 389.093456 -231.190546) (xy 389.093456 -231.08539) (xy 388.508494 -230.500428) (xy 388.508494 -230.397558)
				(xy 389.672576 -229.233476) (xy 389.672576 -229.070916) (xy 389.198358 -228.596698) (xy 389.059928 -228.596698)
				(xy 388.718806 -228.93782) (xy 388.659116 -228.93782) (xy 388.552182 -228.830886) (xy 388.552182 -228.78923)
				(xy 388.982458 -228.358954) (xy 388.982458 -228.297486) (xy 388.37743 -227.692458) (xy 388.37743 -227.6094)
				(xy 388.58571 -227.40112) (xy 388.58571 -227.327714) (xy 388.234682 -226.976686) (xy 388.234682 -226.877626)
				(xy 388.395464 -226.716844) (xy 388.395464 -226.657408) (xy 388.00278 -226.264724) (xy 388.00278 -226.227132)
				(xy 388.115556 -226.114356) (xy 388.115556 -225.760788) (xy 387.3246 -224.969832) (xy 387.266688 -224.969832)
				(xy 387.209284 -224.912428) (xy 387.209284 -218.228164) (xy 387.1849 -218.20378) (xy 387.184646 -214.835486)
				(xy 387.744716 -214.275416) (xy 387.744716 -214.27567) (xy 388.165594 -213.854792) (xy 388.165594 -213.529672)
				(xy 387.983222 -213.3473) (xy 387.983222 -212.89391) (xy 388.10819 -212.768942) (xy 388.10819 -212.056218)
				(xy 387.872732 -211.82076) (xy 387.872732 -210.965288) (xy 388.822184 -210.965034) (xy 388.916164 -210.871054)
				(xy 388.919466 -210.871054) (xy 388.986268 -210.804252) (xy 389.861044 -210.804252) (xy 389.861044 -209.646012)
				(xy 389.861044 -209.639154) (xy 389.940546 -209.559652) (xy 391.220706 -209.559652) (xy 391.238486 -209.577432)
				(xy 391.246106 -209.585052) (xy 391.246106 -209.887312) (xy 391.698226 -210.339432) (xy 391.698226 -210.5152)
				(xy 391.569194 -210.644232) (xy 391.086086 -211.12734) (xy 391.086086 -211.218272) (xy 391.414254 -211.54644)
				(xy 391.414254 -211.657946) (xy 391.414254 -212.043772) (xy 391.386568 -212.071458) (xy 391.386568 -212.942932)
				(xy 392.401044 -213.957408) (xy 392.401044 -214.089234) (xy 392.401044 -214.256112) (xy 392.645646 -214.500714)
				(xy 392.645646 -214.782654) (xy 393.637008 -215.774016) (xy 393.637008 -215.909398) (xy 393.637008 -216.400126)
				(xy 394.21689 -216.980008) (xy 394.592048 -216.980008) (xy 394.914628 -217.302588) (xy 394.979906 -217.367866)
				(xy 394.979906 -217.558112) (xy 394.687298 -217.85072) (xy 394.687298 -218.241626) (xy 394.954506 -218.508834)
				(xy 395.195298 -218.508834) (xy 395.195298 -219.310712) (xy 395.014196 -219.491814) (xy 395.014196 -220.574362)
				(xy 395.526514 -221.08668) (xy 395.526514 -221.15145) (xy 395.169898 -221.507812) (xy 395.169898 -229.047548)
			)
		)
	)
	(zone
		(layer "F.Cu")
		(hatch none 0.5)
		(connect_pads
			(clearance 0)
		)
		(min_thickness 0.25)
		(keepout
			(tracks allowed)
			(vias allowed)
			(pads allowed)
			(copperpour allowed)
			(footprints not_allowed)
		)
		(placement
			(enabled no)
			(sheetname "")
		)
		(fill
			(thermal_gap 0.5)
			(thermal_bridge_width 0.5)
			(island_removal_mode 0)
		)
		(polygon
			(pts
				(arc
					(start 7.53999 -347.700092)
					(mid 10.340086 -344.899996)
					(end 13.139928 -347.700092)
				)
				(arc
					(start 13.139928 -347.700092)
					(mid 10.340086 -350.499934)
					(end 7.53999 -347.700092)
				)
			)
		)
	)
	(zone
		(layer "F.Cu")
		(hatch none 0.5)
		(connect_pads
			(clearance 0)
		)
		(min_thickness 0.25)
		(keepout
			(tracks allowed)
			(vias allowed)
			(pads allowed)
			(copperpour allowed)
			(footprints allowed)
		)
		(placement
			(enabled no)
			(sheetname "")
		)
		(fill
			(thermal_gap 0.5)
			(thermal_bridge_width 0.5)
			(island_removal_mode 0)
		)
		(polygon
			(pts
				(xy 29.647642 -217.516456) (xy 29.647642 -217.072718) (xy 31.972758 -217.072718) (xy 31.972758 -217.516456)
			)
		)
	)
	(zone
		(layer "F.Cu")
		(hatch none 0.5)
		(connect_pads
			(clearance 0)
		)
		(min_thickness 0.25)
		(keepout
			(tracks allowed)
			(vias allowed)
			(pads allowed)
			(copperpour allowed)
			(footprints allowed)
		)
		(placement
			(enabled no)
			(sheetname "")
		)
		(fill
			(thermal_gap 0.5)
			(thermal_bridge_width 0.5)
			(island_removal_mode 0)
		)
		(polygon
			(pts
				(xy 157.791658 -292.204902) (xy 157.791658 -291.976302) (xy 159.823658 -291.976302) (xy 159.823658 -292.204902)
			)
		)
	)
	(zone
		(layer "F.Cu")
		(hatch none 0.5)
		(connect_pads
			(clearance 0)
		)
		(min_thickness 0.25)
		(keepout
			(tracks allowed)
			(vias allowed)
			(pads allowed)
			(copperpour allowed)
			(footprints allowed)
		)
		(placement
			(enabled no)
			(sheetname "")
		)
		(fill
			(thermal_gap 0.5)
			(thermal_bridge_width 0.5)
			(island_removal_mode 0)
		)
		(polygon
			(pts
				(xy 407.774902 -280.307034) (xy 405.742902 -280.307034) (xy 405.742902 -280.304748) (xy 405.564086 -280.304748)
				(xy 405.564086 -280.067512) (xy 405.426164 -280.067512) (xy 405.382984 -280.024332) (xy 405.382984 -279.89149)
				(xy 405.382984 -279.587452) (xy 405.455628 -279.514808) (xy 407.995882 -279.514808) (xy 408.137106 -279.656032)
				(xy 408.137106 -279.853136) (xy 408.055572 -279.93467) (xy 408.055572 -280.307034) (xy 407.958036 -280.307034)
				(xy 407.911046 -280.307034)
			)
		)
	)
	(zone
		(layer "F.Cu")
		(hatch none 0.5)
		(connect_pads
			(clearance 0)
		)
		(min_thickness 0.25)
		(keepout
			(tracks allowed)
			(vias allowed)
			(pads allowed)
			(copperpour allowed)
			(footprints allowed)
		)
		(placement
			(enabled no)
			(sheetname "")
		)
		(fill
			(thermal_gap 0.5)
			(thermal_bridge_width 0.5)
			(island_removal_mode 0)
		)
		(polygon
			(pts
				(xy 413.275526 -301.554896) (xy 413.275526 -301.326296) (xy 415.307526 -301.326296) (xy 415.307526 -301.554896)
			)
		)
	)
	(zone
		(layer "F.Cu")
		(hatch none 0.5)
		(connect_pads
			(clearance 0)
		)
		(min_thickness 0.25)
		(keepout
			(tracks allowed)
			(vias allowed)
			(pads allowed)
			(copperpour allowed)
			(footprints allowed)
		)
		(placement
			(enabled no)
			(sheetname "")
		)
		(fill
			(thermal_gap 0.5)
			(thermal_bridge_width 0.5)
			(island_removal_mode 0)
		)
		(polygon
			(pts
				(xy 207.154526 -246.304816) (xy 207.154526 -246.076216) (xy 209.186526 -246.076216) (xy 209.186526 -246.304816)
			)
		)
	)
	(zone
		(layer "F.Cu")
		(hatch none 0.5)
		(connect_pads
			(clearance 0)
		)
		(min_thickness 0.25)
		(keepout
			(tracks not_allowed)
			(vias allowed)
			(pads allowed)
			(copperpour not_allowed)
			(footprints allowed)
		)
		(placement
			(enabled no)
			(sheetname "")
		)
		(fill
			(thermal_gap 0.5)
			(thermal_bridge_width 0.5)
			(island_removal_mode 0)
		)
		(polygon
			(pts
				(xy 415.923222 -180.40858) (xy 415.260282 -180.40858) (xy 415.260282 -181.95798) (xy 415.716974 -181.95798)
				(xy 415.716974 -181.262274) (xy 415.556446 -181.262274) (xy 415.556446 -180.703474) (xy 415.962846 -180.703474)
				(xy 415.962846 -181.262274) (xy 415.742374 -181.262274) (xy 415.742374 -181.95798) (xy 415.869374 -181.95798)
				(xy 415.869374 -181.502304) (xy 416.342322 -181.502304) (xy 416.342322 -181.31155) (xy 416.29076 -181.259988)
				(xy 416.255962 -181.259988) (xy 416.255962 -180.66004) (xy 415.923222 -180.66004)
			)
		)
	)
	(zone
		(layer "F.Cu")
		(hatch none 0.5)
		(connect_pads
			(clearance 0)
		)
		(min_thickness 0.25)
		(keepout
			(tracks allowed)
			(vias allowed)
			(pads allowed)
			(copperpour allowed)
			(footprints allowed)
		)
		(placement
			(enabled no)
			(sheetname "")
		)
		(fill
			(thermal_gap 0.5)
			(thermal_bridge_width 0.5)
			(island_removal_mode 0)
		)
		(polygon
			(pts
				(xy 66.142616 -271.910556) (xy 63.856616 -271.910556) (xy 63.580518 -271.910556) (xy 63.580518 -270.944594)
				(xy 66.511932 -270.944594) (xy 66.511932 -271.910556)
			)
		)
	)
	(zone
		(layer "F.Cu")
		(hatch none 0.5)
		(connect_pads
			(clearance 0)
		)
		(min_thickness 0.25)
		(keepout
			(tracks not_allowed)
			(vias allowed)
			(pads allowed)
			(copperpour not_allowed)
			(footprints allowed)
		)
		(placement
			(enabled no)
			(sheetname "")
		)
		(fill
			(thermal_gap 0.5)
			(thermal_bridge_width 0.5)
			(island_removal_mode 0)
		)
		(polygon
			(pts
				(arc
					(start 15.339822 -160.50006)
					(mid 10.339832 -165.50005)
					(end 5.339842 -160.50006)
				)
				(arc
					(start 5.339842 -160.50006)
					(mid 10.339832 -155.50007)
					(end 15.339822 -160.50006)
				)
			)
		)
	)
	(zone
		(layer "F.Cu")
		(hatch none 0.5)
		(connect_pads
			(clearance 0)
		)
		(min_thickness 0.25)
		(keepout
			(tracks allowed)
			(vias allowed)
			(pads allowed)
			(copperpour allowed)
			(footprints allowed)
		)
		(placement
			(enabled no)
			(sheetname "")
		)
		(fill
			(thermal_gap 0.5)
			(thermal_bridge_width 0.5)
			(island_removal_mode 0)
		)
		(polygon
			(pts
				(xy 420.30015 -152.305004) (xy 418.968174 -152.305004) (xy 418.769292 -152.106122) (xy 418.769292 -150.314152)
				(xy 419.57244 -149.511004) (xy 422.050464 -149.511004) (xy 423.410126 -150.870666) (xy 423.410126 -154.175714)
				(xy 424.5864 -155.351988) (xy 424.5864 -156.817568) (xy 424.020488 -157.38348) (xy 422.388792 -157.38348)
				(xy 421.740838 -158.031688) (xy 418.879528 -158.031688) (xy 417.718494 -156.870654) (xy 417.718494 -155.15463)
				(xy 418.275008 -154.598116) (xy 420.423594 -154.598116) (xy 420.492174 -154.529536) (xy 420.492174 -152.497028)
			)
		)
	)
	(zone
		(layer "F.Cu")
		(hatch none 0.5)
		(connect_pads
			(clearance 0)
		)
		(min_thickness 0.25)
		(keepout
			(tracks allowed)
			(vias allowed)
			(pads allowed)
			(copperpour allowed)
			(footprints allowed)
		)
		(placement
			(enabled no)
			(sheetname "")
		)
		(fill
			(thermal_gap 0.5)
			(thermal_bridge_width 0.5)
			(island_removal_mode 0)
		)
		(polygon
			(pts
				(xy 137.8077 -220.099128) (xy 138.09472 -220.099128) (xy 138.1252 -220.068648) (xy 138.1252 -219.441268)
				(xy 138.03884 -219.354908) (xy 137.85088 -219.354908) (xy 137.77722 -219.428568) (xy 137.77722 -220.068648)
			)
		)
	)
	(zone
		(layer "F.Cu")
		(hatch none 0.5)
		(connect_pads
			(clearance 0)
		)
		(min_thickness 0.25)
		(keepout
			(tracks allowed)
			(vias allowed)
			(pads allowed)
			(copperpour allowed)
			(footprints allowed)
		)
		(placement
			(enabled no)
			(sheetname "")
		)
		(fill
			(thermal_gap 0.5)
			(thermal_bridge_width 0.5)
			(island_removal_mode 0)
		)
		(polygon
			(pts
				(xy 195.510658 -297.304968) (xy 195.510658 -297.076368) (xy 197.542658 -297.076368) (xy 197.542658 -297.304968)
			)
		)
	)
	(zone
		(layer "F.Cu")
		(hatch none 0.5)
		(connect_pads
			(clearance 0)
		)
		(min_thickness 0.25)
		(keepout
			(tracks allowed)
			(vias allowed)
			(pads allowed)
			(copperpour allowed)
			(footprints allowed)
		)
		(placement
			(enabled no)
			(sheetname "")
		)
		(fill
			(thermal_gap 0.5)
			(thermal_bridge_width 0.5)
			(island_removal_mode 0)
		)
		(polygon
			(pts
				(xy 12.8143 -102.568248) (xy 12.8143 -101.265228) (xy 14.15288 -101.265228) (xy 14.15288 -102.568248)
			)
		)
	)
	(zone
		(layer "F.Cu")
		(hatch none 0.5)
		(connect_pads
			(clearance 0)
		)
		(min_thickness 0.25)
		(keepout
			(tracks allowed)
			(vias allowed)
			(pads allowed)
			(copperpour allowed)
			(footprints allowed)
		)
		(placement
			(enabled no)
			(sheetname "")
		)
		(fill
			(thermal_gap 0.5)
			(thermal_bridge_width 0.5)
			(island_removal_mode 0)
		)
		(polygon
			(pts
				(xy 137.44702 -285.768288) (xy 137.73404 -285.768288) (xy 137.76452 -285.737808) (xy 137.76452 -285.110428)
				(xy 137.67816 -285.024068) (xy 137.4902 -285.024068) (xy 137.41654 -285.097728) (xy 137.41654 -285.737808)
			)
		)
	)
	(zone
		(layer "F.Cu")
		(hatch none 0.5)
		(connect_pads
			(clearance 0)
		)
		(min_thickness 0.25)
		(keepout
			(tracks allowed)
			(vias allowed)
			(pads allowed)
			(copperpour allowed)
			(footprints allowed)
		)
		(placement
			(enabled no)
			(sheetname "")
		)
		(fill
			(thermal_gap 0.5)
			(thermal_bridge_width 0.5)
			(island_removal_mode 0)
		)
		(polygon
			(pts
				(xy 29.647642 -206.46644) (xy 29.647642 -206.022702) (xy 31.972758 -206.022702) (xy 31.972758 -206.46644)
			)
		)
	)
	(zone
		(layer "F.Cu")
		(hatch none 0.5)
		(connect_pads
			(clearance 0)
		)
		(min_thickness 0.25)
		(keepout
			(tracks allowed)
			(vias allowed)
			(pads allowed)
			(copperpour allowed)
			(footprints allowed)
		)
		(placement
			(enabled no)
			(sheetname "")
		)
		(fill
			(thermal_gap 0.5)
			(thermal_bridge_width 0.5)
			(island_removal_mode 0)
		)
		(polygon
			(pts
				(xy 236.21238 -396.466568) (xy 236.21238 -393.189968) (xy 239.61344 -393.189968) (xy 239.61344 -396.466568)
			)
		)
	)
	(zone
		(layer "F.Cu")
		(hatch none 0.5)
		(connect_pads
			(clearance 0)
		)
		(min_thickness 0.25)
		(keepout
			(tracks allowed)
			(vias allowed)
			(pads allowed)
			(copperpour allowed)
			(footprints allowed)
		)
		(placement
			(enabled no)
			(sheetname "")
		)
		(fill
			(thermal_gap 0.5)
			(thermal_bridge_width 0.5)
			(island_removal_mode 0)
		)
		(polygon
			(pts
				(xy 56.37911 -278.272748) (xy 58.704226 -278.272748) (xy 58.742072 -278.272748) (xy 58.742072 -279.203912)
				(xy 56.281828 -279.203912) (xy 56.281828 -278.272748)
			)
		)
	)
	(zone
		(layer "F.Cu")
		(hatch none 0.5)
		(connect_pads
			(clearance 0)
		)
		(min_thickness 0.25)
		(keepout
			(tracks allowed)
			(vias allowed)
			(pads allowed)
			(copperpour allowed)
			(footprints allowed)
		)
		(placement
			(enabled no)
			(sheetname "")
		)
		(fill
			(thermal_gap 0.5)
			(thermal_bridge_width 0.5)
			(island_removal_mode 0)
		)
		(polygon
			(pts
				(xy 161.937954 -268.404848) (xy 161.937954 -268.176248) (xy 163.868354 -268.176248) (xy 163.868354 -268.404848)
			)
		)
	)
	(zone
		(layer "F.Cu")
		(hatch none 0.5)
		(connect_pads
			(clearance 0)
		)
		(min_thickness 0.25)
		(keepout
			(tracks allowed)
			(vias allowed)
			(pads allowed)
			(copperpour allowed)
			(footprints allowed)
		)
		(placement
			(enabled no)
			(sheetname "")
		)
		(fill
			(thermal_gap 0.5)
			(thermal_bridge_width 0.5)
			(island_removal_mode 0)
		)
		(polygon
			(pts
				(xy 15.10284 -109.050328) (xy 15.10284 -108.041948) (xy 16.76908 -108.041948) (xy 16.76908 -109.050328)
			)
		)
	)
	(zone
		(layer "F.Cu")
		(hatch none 0.5)
		(connect_pads
			(clearance 0)
		)
		(min_thickness 0.25)
		(keepout
			(tracks allowed)
			(vias allowed)
			(pads allowed)
			(copperpour allowed)
			(footprints allowed)
		)
		(placement
			(enabled no)
			(sheetname "")
		)
		(fill
			(thermal_gap 0.5)
			(thermal_bridge_width 0.5)
			(island_removal_mode 0)
		)
		(polygon
			(pts
				(xy 11.11631 -226.016566) (xy 11.11631 -225.572828) (xy 13.441426 -225.572828) (xy 13.441426 -226.016566)
			)
		)
	)
	(zone
		(layer "F.Cu")
		(hatch none 0.5)
		(connect_pads
			(clearance 0)
		)
		(min_thickness 0.25)
		(keepout
			(tracks not_allowed)
			(vias allowed)
			(pads allowed)
			(copperpour not_allowed)
			(footprints allowed)
		)
		(placement
			(enabled no)
			(sheetname "")
		)
		(fill
			(thermal_gap 0.5)
			(thermal_bridge_width 0.5)
			(island_removal_mode 0)
		)
		(polygon
			(pts
				(xy 297.39336 -413.84982) (xy 297.39336 -413.66948) (xy 299.43552 -413.66948) (xy 299.43552 -413.84982)
			)
		)
	)
	(zone
		(layer "F.Cu")
		(hatch none 0.5)
		(connect_pads
			(clearance 0)
		)
		(min_thickness 0.25)
		(keepout
			(tracks allowed)
			(vias allowed)
			(pads allowed)
			(copperpour allowed)
			(footprints allowed)
		)
		(placement
			(enabled no)
			(sheetname "")
		)
		(fill
			(thermal_gap 0.5)
			(thermal_bridge_width 0.5)
			(island_removal_mode 0)
		)
		(polygon
			(pts
				(xy 136.42086 -217.663268) (xy 136.70788 -217.663268) (xy 136.73836 -217.632788) (xy 136.73836 -217.005408)
				(xy 136.652 -216.919048) (xy 136.46404 -216.919048) (xy 136.39038 -216.992708) (xy 136.39038 -217.632788)
			)
		)
	)
	(zone
		(layer "F.Cu")
		(hatch none 0.5)
		(connect_pads
			(clearance 0)
		)
		(min_thickness 0.25)
		(keepout
			(tracks allowed)
			(vias allowed)
			(pads allowed)
			(copperpour allowed)
			(footprints allowed)
		)
		(placement
			(enabled no)
			(sheetname "")
		)
		(fill
			(thermal_gap 0.5)
			(thermal_bridge_width 0.5)
			(island_removal_mode 0)
		)
		(polygon
			(pts
				(xy 390.691624 -410.948886) (xy 390.691624 -406.105868) (xy 392.57605 -406.105868) (xy 392.57605 -410.948886)
			)
		)
	)
	(zone
		(layer "F.Cu")
		(hatch none 0.5)
		(connect_pads
			(clearance 0)
		)
		(min_thickness 0.25)
		(keepout
			(tracks allowed)
			(vias allowed)
			(pads allowed)
			(copperpour allowed)
			(footprints allowed)
		)
		(placement
			(enabled no)
			(sheetname "")
		)
		(fill
			(thermal_gap 0.5)
			(thermal_bridge_width 0.5)
			(island_removal_mode 0)
		)
		(polygon
			(pts
				(xy 93.31706 -339.047328) (xy 93.31706 -334.493108) (xy 107.2896 -334.493108) (xy 107.2896 -339.047328)
			)
		)
	)
	(zone
		(layer "F.Cu")
		(hatch none 0.5)
		(connect_pads
			(clearance 0)
		)
		(min_thickness 0.25)
		(keepout
			(tracks not_allowed)
			(vias allowed)
			(pads allowed)
			(copperpour not_allowed)
			(footprints allowed)
		)
		(placement
			(enabled no)
			(sheetname "")
		)
		(fill
			(thermal_gap 0.5)
			(thermal_bridge_width 0.5)
			(island_removal_mode 0)
		)
		(polygon
			(pts
				(xy 111.274352 -335.753456) (xy 111.516668 -335.753456) (xy 111.516668 -335.679288) (xy 111.274352 -335.679288)
			)
		)
	)
	(zone
		(layer "F.Cu")
		(hatch none 0.5)
		(connect_pads
			(clearance 0)
		)
		(min_thickness 0.25)
		(keepout
			(tracks allowed)
			(vias allowed)
			(pads allowed)
			(copperpour allowed)
			(footprints allowed)
		)
		(placement
			(enabled no)
			(sheetname "")
		)
		(fill
			(thermal_gap 0.5)
			(thermal_bridge_width 0.5)
			(island_removal_mode 0)
		)
		(polygon
			(pts
				(xy 292.67531 -211.566506) (xy 292.67531 -211.122768) (xy 295.000426 -211.122768) (xy 295.000426 -211.566506)
			)
		)
	)
	(zone
		(layer "F.Cu")
		(hatch none 0.5)
		(connect_pads
			(clearance 0)
		)
		(min_thickness 0.25)
		(keepout
			(tracks allowed)
			(vias allowed)
			(pads allowed)
			(copperpour allowed)
			(footprints allowed)
		)
		(placement
			(enabled no)
			(sheetname "")
		)
		(fill
			(thermal_gap 0.5)
			(thermal_bridge_width 0.5)
			(island_removal_mode 0)
		)
		(polygon
			(pts
				(xy 289.231578 -280.416508) (xy 289.231578 -279.97277) (xy 291.556694 -279.97277) (xy 291.556694 -280.416508)
			)
		)
	)
	(zone
		(layer "F.Cu")
		(hatch none 0.5)
		(connect_pads
			(clearance 0)
		)
		(min_thickness 0.25)
		(keepout
			(tracks allowed)
			(vias allowed)
			(pads allowed)
			(copperpour allowed)
			(footprints allowed)
		)
		(placement
			(enabled no)
			(sheetname "")
		)
		(fill
			(thermal_gap 0.5)
			(thermal_bridge_width 0.5)
			(island_removal_mode 0)
		)
		(polygon
			(pts
				(xy 29.647642 -289.766502) (xy 29.647642 -289.322764) (xy 31.972758 -289.322764) (xy 31.972758 -289.766502)
			)
		)
	)
	(zone
		(layer "F.Cu")
		(hatch none 0.5)
		(connect_pads
			(clearance 0)
		)
		(min_thickness 0.25)
		(keepout
			(tracks allowed)
			(vias allowed)
			(pads allowed)
			(copperpour allowed)
			(footprints allowed)
		)
		(placement
			(enabled no)
			(sheetname "")
		)
		(fill
			(thermal_gap 0.5)
			(thermal_bridge_width 0.5)
			(island_removal_mode 0)
		)
		(polygon
			(pts
				(xy 26.20391 -203.916534) (xy 26.20391 -203.472796) (xy 28.529026 -203.472796) (xy 28.529026 -203.916534)
			)
		)
	)
	(zone
		(layer "F.Cu")
		(hatch none 0.5)
		(connect_pads
			(clearance 0)
		)
		(min_thickness 0.25)
		(keepout
			(tracks allowed)
			(vias allowed)
			(pads allowed)
			(copperpour allowed)
			(footprints not_allowed)
		)
		(placement
			(enabled no)
			(sheetname "")
		)
		(fill
			(thermal_gap 0.5)
			(thermal_bridge_width 0.5)
			(island_removal_mode 0)
		)
		(polygon
			(pts
				(arc
					(start 325.854822 -353.525074)
					(mid 329.854814 -349.525082)
					(end 333.854806 -353.525074)
				)
				(arc
					(start 333.854806 -353.525074)
					(mid 329.854814 -357.525066)
					(end 325.854822 -353.525074)
				)
			)
		)
	)
	(zone
		(layer "F.Cu")
		(hatch none 0.5)
		(connect_pads
			(clearance 0)
		)
		(min_thickness 0.25)
		(keepout
			(tracks allowed)
			(vias allowed)
			(pads allowed)
			(copperpour allowed)
			(footprints allowed)
		)
		(placement
			(enabled no)
			(sheetname "")
		)
		(fill
			(thermal_gap 0.5)
			(thermal_bridge_width 0.5)
			(island_removal_mode 0)
		)
		(polygon
			(pts
				(xy 207.154526 -203.576428) (xy 209.186526 -203.576428) (xy 209.186526 -203.805028) (xy 207.154526 -203.805028)
				(xy 207.018382 -203.805028) (xy 206.971392 -203.805028) (xy 206.971392 -203.576428) (xy 207.018382 -203.576428)
			)
		)
	)
	(zone
		(layer "F.Cu")
		(hatch none 0.5)
		(connect_pads
			(clearance 0)
		)
		(min_thickness 0.25)
		(keepout
			(tracks allowed)
			(vias allowed)
			(pads allowed)
			(copperpour allowed)
			(footprints allowed)
		)
		(placement
			(enabled no)
			(sheetname "")
		)
		(fill
			(thermal_gap 0.5)
			(thermal_bridge_width 0.5)
			(island_removal_mode 0)
		)
		(polygon
			(pts
				(xy 292.67531 -271.066514) (xy 292.67531 -270.622776) (xy 295.000426 -270.622776) (xy 295.000426 -271.066514)
			)
		)
	)
	(zone
		(layer "F.Cu")
		(hatch none 0.5)
		(connect_pads
			(clearance 0)
		)
		(min_thickness 0.25)
		(keepout
			(tracks allowed)
			(vias allowed)
			(pads allowed)
			(copperpour allowed)
			(footprints allowed)
		)
		(placement
			(enabled no)
			(sheetname "")
		)
		(fill
			(thermal_gap 0.5)
			(thermal_bridge_width 0.5)
			(island_removal_mode 0)
		)
		(polygon
			(pts
				(xy 424.919394 -206.976472) (xy 426.951394 -206.976472) (xy 426.951394 -207.205072) (xy 424.919394 -207.205072)
				(xy 424.78325 -207.205072) (xy 424.73626 -207.205072) (xy 424.73626 -206.976472) (xy 424.78325 -206.976472)
			)
		)
	)
	(zone
		(layer "F.Cu")
		(hatch none 0.5)
		(connect_pads
			(clearance 0)
		)
		(min_thickness 0.25)
		(keepout
			(tracks allowed)
			(vias allowed)
			(pads allowed)
			(copperpour allowed)
			(footprints allowed)
		)
		(placement
			(enabled no)
			(sheetname "")
		)
		(fill
			(thermal_gap 0.5)
			(thermal_bridge_width 0.5)
			(island_removal_mode 0)
		)
		(polygon
			(pts
				(xy 424.919394 -281.776424) (xy 426.951394 -281.776424) (xy 426.951394 -282.005024) (xy 424.919394 -282.005024)
				(xy 424.78325 -282.005024) (xy 424.73626 -282.005024) (xy 424.73626 -281.776424) (xy 424.78325 -281.776424)
			)
		)
	)
	(zone
		(layer "F.Cu")
		(hatch none 0.5)
		(connect_pads
			(clearance 0)
		)
		(min_thickness 0.25)
		(keepout
			(tracks allowed)
			(vias allowed)
			(pads allowed)
			(copperpour allowed)
			(footprints allowed)
		)
		(placement
			(enabled no)
			(sheetname "")
		)
		(fill
			(thermal_gap 0.5)
			(thermal_bridge_width 0.5)
			(island_removal_mode 0)
		)
		(polygon
			(pts
				(xy 14.560042 -287.216596) (xy 14.560042 -286.772858) (xy 16.885158 -286.772858) (xy 16.885158 -287.216596)
			)
		)
	)
	(zone
		(layer "F.Cu")
		(hatch none 0.5)
		(connect_pads
			(clearance 0)
		)
		(min_thickness 0.25)
		(keepout
			(tracks allowed)
			(vias allowed)
			(pads allowed)
			(copperpour allowed)
			(footprints allowed)
		)
		(placement
			(enabled no)
			(sheetname "")
		)
		(fill
			(thermal_gap 0.5)
			(thermal_bridge_width 0.5)
			(island_removal_mode 0)
		)
		(polygon
			(pts
				(xy 274.143978 -303.366424) (xy 274.143978 -302.922686) (xy 276.469094 -302.922686) (xy 276.469094 -303.366424)
			)
		)
	)
	(zone
		(layer "F.Cu")
		(hatch none 0.5)
		(connect_pads
			(clearance 0)
		)
		(min_thickness 0.25)
		(keepout
			(tracks allowed)
			(vias allowed)
			(pads allowed)
			(copperpour allowed)
			(footprints allowed)
		)
		(placement
			(enabled no)
			(sheetname "")
		)
		(fill
			(thermal_gap 0.5)
			(thermal_bridge_width 0.5)
			(island_removal_mode 0)
		)
		(polygon
			(pts
				(xy 210.598258 -226.754944) (xy 210.598258 -226.526344) (xy 212.630258 -226.526344) (xy 212.630258 -226.754944)
			)
		)
	)
	(zone
		(layer "F.Cu")
		(hatch none 0.5)
		(connect_pads
			(clearance 0)
		)
		(min_thickness 0.25)
		(keepout
			(tracks allowed)
			(vias allowed)
			(pads allowed)
			(copperpour allowed)
			(footprints allowed)
		)
		(placement
			(enabled no)
			(sheetname "")
		)
		(fill
			(thermal_gap 0.5)
			(thermal_bridge_width 0.5)
			(island_removal_mode 0)
		)
		(polygon
			(pts
				(xy 415.307526 -239.504982) (xy 413.275526 -239.504982) (xy 413.089344 -239.504982) (xy 413.089344 -238.750856)
				(xy 415.507424 -238.750856) (xy 415.507424 -239.504982)
			)
		)
	)
	(zone
		(layer "F.Cu")
		(hatch none 0.5)
		(connect_pads
			(clearance 0)
		)
		(min_thickness 0.25)
		(keepout
			(tracks allowed)
			(vias allowed)
			(pads allowed)
			(copperpour allowed)
			(footprints allowed)
		)
		(placement
			(enabled no)
			(sheetname "")
		)
		(fill
			(thermal_gap 0.5)
			(thermal_bridge_width 0.5)
			(island_removal_mode 0)
		)
		(polygon
			(pts
				(xy 443.450726 -252.25502) (xy 443.450726 -252.02642) (xy 445.482726 -252.02642) (xy 445.482726 -252.25502)
			)
		)
	)
	(zone
		(layer "F.Cu")
		(hatch none 0.5)
		(connect_pads
			(clearance 0)
		)
		(min_thickness 0.25)
		(keepout
			(tracks allowed)
			(vias allowed)
			(pads allowed)
			(copperpour allowed)
			(footprints allowed)
		)
		(placement
			(enabled no)
			(sheetname "")
		)
		(fill
			(thermal_gap 0.5)
			(thermal_bridge_width 0.5)
			(island_removal_mode 0)
		)
		(polygon
			(pts
				(xy 192.066926 -268.404848) (xy 192.066926 -268.176248) (xy 194.098926 -268.176248) (xy 194.098926 -268.404848)
			)
		)
	)
	(zone
		(layer "F.Cu")
		(hatch none 0.5)
		(connect_pads
			(clearance 0)
		)
		(min_thickness 0.25)
		(keepout
			(tracks allowed)
			(vias allowed)
			(pads allowed)
			(copperpour allowed)
			(footprints not_allowed)
		)
		(placement
			(enabled no)
			(sheetname "")
		)
		(fill
			(thermal_gap 0.5)
			(thermal_bridge_width 0.5)
			(island_removal_mode 0)
		)
		(polygon
			(pts
				(xy 7.140702 -330.091796) (xy 13.240512 -330.091796) (xy 13.240512 -186.09183) (xy 7.140702 -186.09183)
			)
		)
	)
	(zone
		(layer "F.Cu")
		(hatch none 0.5)
		(connect_pads
			(clearance 0)
		)
		(min_thickness 0.25)
		(keepout
			(tracks allowed)
			(vias allowed)
			(pads allowed)
			(copperpour allowed)
			(footprints allowed)
		)
		(placement
			(enabled no)
			(sheetname "")
		)
		(fill
			(thermal_gap 0.5)
			(thermal_bridge_width 0.5)
			(island_removal_mode 0)
		)
		(polygon
			(pts
				(xy 274.143978 -265.966448) (xy 274.143978 -265.52271) (xy 276.469094 -265.52271) (xy 276.469094 -265.966448)
			)
		)
	)
	(zone
		(layer "F.Cu")
		(hatch none 0.5)
		(connect_pads
			(clearance 0)
		)
		(min_thickness 0.25)
		(keepout
			(tracks allowed)
			(vias allowed)
			(pads allowed)
			(copperpour allowed)
			(footprints allowed)
		)
		(placement
			(enabled no)
			(sheetname "")
		)
		(fill
			(thermal_gap 0.5)
			(thermal_bridge_width 0.5)
			(island_removal_mode 0)
		)
		(polygon
			(pts
				(xy 55.70728 -164.229288) (xy 55.70728 -162.413188) (xy 57.0865 -162.413188) (xy 57.0865 -164.229288)
			)
		)
	)
	(zone
		(layer "F.Cu")
		(hatch none 0.5)
		(connect_pads
			(clearance 0)
		)
		(min_thickness 0.25)
		(keepout
			(tracks not_allowed)
			(vias allowed)
			(pads allowed)
			(copperpour not_allowed)
			(footprints allowed)
		)
		(placement
			(enabled no)
			(sheetname "")
		)
		(fill
			(thermal_gap 0.5)
			(thermal_bridge_width 0.5)
			(island_removal_mode 0)
		)
		(polygon
			(pts
				(xy 86.792816 -339.16366) (xy 87.035132 -339.16366) (xy 87.035132 -339.085428) (xy 86.792816 -339.085428)
			)
		)
	)
	(zone
		(layer "F.Cu")
		(hatch none 0.5)
		(connect_pads
			(clearance 0)
		)
		(min_thickness 0.25)
		(keepout
			(tracks allowed)
			(vias allowed)
			(pads allowed)
			(copperpour allowed)
			(footprints not_allowed)
		)
		(placement
			(enabled no)
			(sheetname "")
		)
		(fill
			(thermal_gap 0.5)
			(thermal_bridge_width 0.5)
			(island_removal_mode 0)
		)
		(polygon
			(pts
				(arc
					(start 134.918958 -354.434902)
					(mid 136.518904 -352.834956)
					(end 138.11885 -354.434902)
				)
				(arc
					(start 138.11885 -354.434902)
					(mid 136.518904 -356.034848)
					(end 134.918958 -354.434902)
				)
			)
		)
	)
	(zone
		(layer "F.Cu")
		(hatch none 0.5)
		(connect_pads
			(clearance 0)
		)
		(min_thickness 0.25)
		(keepout
			(tracks allowed)
			(vias allowed)
			(pads allowed)
			(copperpour allowed)
			(footprints allowed)
		)
		(placement
			(enabled no)
			(sheetname "")
		)
		(fill
			(thermal_gap 0.5)
			(thermal_bridge_width 0.5)
			(island_removal_mode 0)
		)
		(polygon
			(pts
				(xy 44.735242 -206.46644) (xy 44.735242 -206.022702) (xy 47.060358 -206.022702) (xy 47.060358 -206.46644)
			)
		)
	)
	(zone
		(layer "F.Cu")
		(hatch none 0.5)
		(connect_pads
			(clearance 0)
		)
		(min_thickness 0.25)
		(keepout
			(tracks not_allowed)
			(vias allowed)
			(pads allowed)
			(copperpour not_allowed)
			(footprints allowed)
		)
		(placement
			(enabled no)
			(sheetname "")
		)
		(fill
			(thermal_gap 0.5)
			(thermal_bridge_width 0.5)
			(island_removal_mode 0)
		)
		(polygon
			(pts
				(arc
					(start 239.450118 -272.50009)
					(mid 236.650022 -275.300186)
					(end 233.849926 -272.50009)
				)
				(arc
					(start 233.849926 -272.50009)
					(mid 236.650022 -269.699994)
					(end 239.450118 -272.50009)
				)
			)
		)
	)
	(zone
		(layer "F.Cu")
		(hatch none 0.5)
		(connect_pads
			(clearance 0)
		)
		(min_thickness 0.25)
		(keepout
			(tracks allowed)
			(vias allowed)
			(pads allowed)
			(copperpour allowed)
			(footprints allowed)
		)
		(placement
			(enabled no)
			(sheetname "")
		)
		(fill
			(thermal_gap 0.5)
			(thermal_bridge_width 0.5)
			(island_removal_mode 0)
		)
		(polygon
			(pts
				(xy 195.510658 -231.85501) (xy 195.510658 -231.62641) (xy 197.542658 -231.62641) (xy 197.542658 -231.85501)
			)
		)
	)
	(zone
		(layer "F.Cu")
		(hatch none 0.5)
		(connect_pads
			(clearance 0)
		)
		(min_thickness 0.25)
		(keepout
			(tracks allowed)
			(vias allowed)
			(pads allowed)
			(copperpour allowed)
			(footprints allowed)
		)
		(placement
			(enabled no)
			(sheetname "")
		)
		(fill
			(thermal_gap 0.5)
			(thermal_bridge_width 0.5)
			(island_removal_mode 0)
		)
		(polygon
			(pts
				(xy 88.86698 -215.229948) (xy 89.154 -215.229948) (xy 89.18448 -215.199468) (xy 89.18448 -214.572088)
				(xy 89.09812 -214.485728) (xy 88.91016 -214.485728) (xy 88.8365 -214.559388) (xy 88.8365 -215.199468)
			)
		)
	)
	(zone
		(layer "F.Cu")
		(hatch none 0.5)
		(connect_pads
			(clearance 0)
		)
		(min_thickness 0.25)
		(keepout
			(tracks allowed)
			(vias allowed)
			(pads allowed)
			(copperpour allowed)
			(footprints allowed)
		)
		(placement
			(enabled no)
			(sheetname "")
		)
		(fill
			(thermal_gap 0.5)
			(thermal_bridge_width 0.5)
			(island_removal_mode 0)
		)
		(polygon
			(pts
				(xy 207.154526 -220.576394) (xy 209.186526 -220.576394) (xy 209.186526 -220.804994) (xy 207.154526 -220.804994)
				(xy 207.018382 -220.804994) (xy 206.971392 -220.804994) (xy 206.971392 -220.576394) (xy 207.018382 -220.576394)
			)
		)
	)
	(zone
		(layer "F.Cu")
		(hatch none 0.5)
		(connect_pads
			(clearance 0)
		)
		(min_thickness 0.25)
		(keepout
			(tracks allowed)
			(vias allowed)
			(pads allowed)
			(copperpour allowed)
			(footprints allowed)
		)
		(placement
			(enabled no)
			(sheetname "")
		)
		(fill
			(thermal_gap 0.5)
			(thermal_bridge_width 0.5)
			(island_removal_mode 0)
		)
		(polygon
			(pts
				(xy 443.450726 -231.85501) (xy 443.450726 -231.62641) (xy 445.482726 -231.62641) (xy 445.482726 -231.85501)
			)
		)
	)
	(zone
		(layer "F.Cu")
		(hatch none 0.5)
		(connect_pads
			(clearance 0)
		)
		(min_thickness 0.25)
		(keepout
			(tracks not_allowed)
			(vias allowed)
			(pads allowed)
			(copperpour not_allowed)
			(footprints allowed)
		)
		(placement
			(enabled no)
			(sheetname "")
		)
		(fill
			(thermal_gap 0.5)
			(thermal_bridge_width 0.5)
			(island_removal_mode 0)
		)
		(polygon
			(pts
				(xy 135.755888 -344.518488) (xy 135.998204 -344.518488) (xy 135.998204 -343.543128) (xy 135.755888 -343.543128)
			)
		)
	)
	(zone
		(layer "F.Cu")
		(hatch none 0.5)
		(connect_pads
			(clearance 0)
		)
		(min_thickness 0.25)
		(keepout
			(tracks allowed)
			(vias allowed)
			(pads allowed)
			(copperpour allowed)
			(footprints allowed)
		)
		(placement
			(enabled no)
			(sheetname "")
		)
		(fill
			(thermal_gap 0.5)
			(thermal_bridge_width 0.5)
			(island_removal_mode 0)
		)
		(polygon
			(pts
				(xy 402.944584 -410.948886) (xy 402.944584 -406.105868) (xy 404.82901 -406.105868) (xy 404.82901 -410.948886)
			)
		)
	)
	(zone
		(layer "F.Cu")
		(hatch none 0.5)
		(connect_pads
			(clearance 0)
		)
		(min_thickness 0.25)
		(keepout
			(tracks allowed)
			(vias allowed)
			(pads allowed)
			(copperpour allowed)
			(footprints allowed)
		)
		(placement
			(enabled no)
			(sheetname "")
		)
		(fill
			(thermal_gap 0.5)
			(thermal_bridge_width 0.5)
			(island_removal_mode 0)
		)
		(polygon
			(pts
				(xy 176.4538 -31.229808) (xy 176.4538 -30.165548) (xy 176.08042 -29.792168) (xy 175.77816 -29.792168)
				(xy 175.14316 -30.427168) (xy 175.14316 -31.448248) (xy 175.46828 -31.773368) (xy 175.91024 -31.773368)
			)
		)
	)
	(zone
		(layer "F.Cu")
		(hatch none 0.5)
		(connect_pads
			(clearance 0)
		)
		(min_thickness 0.25)
		(keepout
			(tracks allowed)
			(vias allowed)
			(pads allowed)
			(copperpour allowed)
			(footprints allowed)
		)
		(placement
			(enabled no)
			(sheetname "")
		)
		(fill
			(thermal_gap 0.5)
			(thermal_bridge_width 0.5)
			(island_removal_mode 0)
		)
		(polygon
			(pts
				(xy 412.134304 -410.948886) (xy 412.134304 -406.105868) (xy 414.01873 -406.105868) (xy 414.01873 -410.948886)
			)
		)
	)
	(zone
		(layer "F.Cu")
		(hatch none 0.5)
		(connect_pads
			(clearance 0)
		)
		(min_thickness 0.25)
		(keepout
			(tracks allowed)
			(vias allowed)
			(pads allowed)
			(copperpour allowed)
			(footprints allowed)
		)
		(placement
			(enabled no)
			(sheetname "")
		)
		(fill
			(thermal_gap 0.5)
			(thermal_bridge_width 0.5)
			(island_removal_mode 0)
		)
		(polygon
			(pts
				(xy 409.071064 -410.948886) (xy 409.071064 -406.105868) (xy 410.95549 -406.105868) (xy 410.95549 -410.948886)
			)
		)
	)
	(zone
		(layer "F.Cu")
		(hatch none 0.5)
		(connect_pads
			(clearance 0)
		)
		(min_thickness 0.25)
		(keepout
			(tracks not_allowed)
			(vias allowed)
			(pads allowed)
			(copperpour not_allowed)
			(footprints allowed)
		)
		(placement
			(enabled no)
			(sheetname "")
		)
		(fill
			(thermal_gap 0.5)
			(thermal_bridge_width 0.5)
			(island_removal_mode 0)
		)
		(polygon
			(pts
				(arc
					(start 263.645396 -51.999896)
					(mid 268.645386 -46.999906)
					(end 273.645376 -51.999896)
				)
				(arc
					(start 273.645376 -51.999896)
					(mid 268.645386 -56.999886)
					(end 263.645396 -51.999896)
				)
			)
		)
	)
	(zone
		(layer "F.Cu")
		(hatch none 0.5)
		(connect_pads
			(clearance 0)
		)
		(min_thickness 0.25)
		(keepout
			(tracks allowed)
			(vias allowed)
			(pads allowed)
			(copperpour allowed)
			(footprints allowed)
		)
		(placement
			(enabled no)
			(sheetname "")
		)
		(fill
			(thermal_gap 0.5)
			(thermal_bridge_width 0.5)
			(island_removal_mode 0)
		)
		(polygon
			(pts
				(xy 64.002412 -245.566438) (xy 64.002412 -245.1227) (xy 66.186812 -245.1227) (xy 66.186812 -245.566438)
			)
		)
	)
	(zone
		(layer "F.Cu")
		(hatch none 0.5)
		(connect_pads
			(clearance 0)
		)
		(min_thickness 0.25)
		(keepout
			(tracks allowed)
			(vias allowed)
			(pads allowed)
			(copperpour allowed)
			(footprints allowed)
		)
		(placement
			(enabled no)
			(sheetname "")
		)
		(fill
			(thermal_gap 0.5)
			(thermal_bridge_width 0.5)
			(island_removal_mode 0)
		)
		(polygon
			(pts
				(xy 416.615626 -155.601924) (xy 420.621206 -155.601924) (xy 421.101266 -155.121864) (xy 421.101266 -153.056844)
				(xy 420.829486 -152.785064) (xy 418.975286 -152.785064) (xy 418.723826 -152.533604) (xy 418.723826 -150.613364)
				(xy 418.307266 -150.196804) (xy 416.816286 -150.196804) (xy 416.168586 -150.844504) (xy 416.168586 -155.154884)
			)
		)
	)
	(zone
		(layer "F.Cu")
		(hatch none 0.5)
		(connect_pads
			(clearance 0)
		)
		(min_thickness 0.25)
		(keepout
			(tracks allowed)
			(vias allowed)
			(pads allowed)
			(copperpour allowed)
			(footprints not_allowed)
		)
		(placement
			(enabled no)
			(sheetname "")
		)
		(fill
			(thermal_gap 0.5)
			(thermal_bridge_width 0.5)
			(island_removal_mode 0)
		)
		(polygon
			(pts
				(xy 365.300006 -440.989974) (xy 365.300006 -418.869876) (xy 354.24999 -418.869876) (xy 354.24999 -440.989974)
			)
		)
	)
	(zone
		(layer "F.Cu")
		(hatch none 0.5)
		(connect_pads
			(clearance 0)
		)
		(min_thickness 0.25)
		(keepout
			(tracks allowed)
			(vias allowed)
			(pads allowed)
			(copperpour allowed)
			(footprints allowed)
		)
		(placement
			(enabled no)
			(sheetname "")
		)
		(fill
			(thermal_gap 0.5)
			(thermal_bridge_width 0.5)
			(island_removal_mode 0)
		)
		(polygon
			(pts
				(xy 161.891726 -298.77639) (xy 163.923726 -298.77639) (xy 163.923726 -299.00499) (xy 161.891726 -299.00499)
				(xy 161.755582 -299.00499) (xy 161.708592 -299.00499) (xy 161.708592 -298.77639) (xy 161.755582 -298.77639)
			)
		)
	)
	(zone
		(layer "F.Cu")
		(hatch none 0.5)
		(connect_pads
			(clearance 0)
		)
		(min_thickness 0.25)
		(keepout
			(tracks not_allowed)
			(vias allowed)
			(pads allowed)
			(copperpour not_allowed)
			(footprints allowed)
		)
		(placement
			(enabled no)
			(sheetname "")
		)
		(fill
			(thermal_gap 0.5)
			(thermal_bridge_width 0.5)
			(island_removal_mode 0)
		)
		(polygon
			(pts
				(arc
					(start 208.399888 -22.29993)
					(mid 203.399898 -27.29992)
					(end 198.399908 -22.29993)
				)
				(arc
					(start 198.399908 -22.29993)
					(mid 203.399898 -17.29994)
					(end 208.399888 -22.29993)
				)
			)
		)
	)
	(zone
		(layer "F.Cu")
		(hatch none 0.5)
		(connect_pads
			(clearance 0)
		)
		(min_thickness 0.25)
		(keepout
			(tracks allowed)
			(vias allowed)
			(pads allowed)
			(copperpour allowed)
			(footprints allowed)
		)
		(placement
			(enabled no)
			(sheetname "")
		)
		(fill
			(thermal_gap 0.5)
			(thermal_bridge_width 0.5)
			(island_removal_mode 0)
		)
		(polygon
			(pts
				(xy 63.951612 -272.322798) (xy 66.237612 -272.322798) (xy 66.51371 -272.322798) (xy 66.51371 -273.28876)
				(xy 63.582296 -273.28876) (xy 63.582296 -272.322798)
			)
		)
	)
	(zone
		(layer "F.Cu")
		(hatch none 0.5)
		(connect_pads
			(clearance 0)
		)
		(min_thickness 0.25)
		(keepout
			(tracks allowed)
			(vias allowed)
			(pads allowed)
			(copperpour allowed)
			(footprints allowed)
		)
		(placement
			(enabled no)
			(sheetname "")
		)
		(fill
			(thermal_gap 0.5)
			(thermal_bridge_width 0.5)
			(island_removal_mode 0)
		)
		(polygon
			(pts
				(xy 431.02784 -166.093648) (xy 431.02784 -163.497768) (xy 431.673 -163.497768) (xy 431.673 -166.093648)
			)
		)
	)
	(zone
		(layer "F.Cu")
		(hatch none 0.5)
		(connect_pads
			(clearance 0)
		)
		(min_thickness 0.25)
		(keepout
			(tracks allowed)
			(vias allowed)
			(pads allowed)
			(copperpour allowed)
			(footprints allowed)
		)
		(placement
			(enabled no)
			(sheetname "")
		)
		(fill
			(thermal_gap 0.5)
			(thermal_bridge_width 0.5)
			(island_removal_mode 0)
		)
		(polygon
			(pts
				(xy 428.363126 -269.254986) (xy 428.363126 -269.026386) (xy 430.395126 -269.026386) (xy 430.395126 -269.254986)
			)
		)
	)
	(zone
		(layer "F.Cu")
		(hatch none 0.5)
		(connect_pads
			(clearance 0)
		)
		(min_thickness 0.25)
		(keepout
			(tracks allowed)
			(vias allowed)
			(pads allowed)
			(copperpour allowed)
			(footprints allowed)
		)
		(placement
			(enabled no)
			(sheetname "")
		)
		(fill
			(thermal_gap 0.5)
			(thermal_bridge_width 0.5)
			(island_removal_mode 0)
		)
		(polygon
			(pts
				(xy 180.423058 -267.554964) (xy 180.423058 -267.326364) (xy 182.455058 -267.326364) (xy 182.455058 -267.554964)
			)
		)
	)
	(zone
		(layer "F.Cu")
		(hatch none 0.5)
		(connect_pads
			(clearance 0)
		)
		(min_thickness 0.25)
		(keepout
			(tracks allowed)
			(vias allowed)
			(pads allowed)
			(copperpour allowed)
			(footprints allowed)
		)
		(placement
			(enabled no)
			(sheetname "")
		)
		(fill
			(thermal_gap 0.5)
			(thermal_bridge_width 0.5)
			(island_removal_mode 0)
		)
		(polygon
			(pts
				(xy 366.886236 -331.689456) (xy 366.886236 -335.695036) (xy 367.366296 -336.175096) (xy 369.431316 -336.175096)
				(xy 369.703096 -335.903316) (xy 369.703096 -334.049116) (xy 369.954556 -333.797656) (xy 371.874796 -333.797656)
				(xy 372.291356 -333.381096) (xy 372.291356 -331.890116) (xy 371.643656 -331.242416) (xy 367.333276 -331.242416)
			)
		)
	)
	(zone
		(layer "F.Cu")
		(hatch none 0.5)
		(connect_pads
			(clearance 0)
		)
		(min_thickness 0.25)
		(keepout
			(tracks allowed)
			(vias allowed)
			(pads allowed)
			(copperpour allowed)
			(footprints allowed)
		)
		(placement
			(enabled no)
			(sheetname "")
		)
		(fill
			(thermal_gap 0.5)
			(thermal_bridge_width 0.5)
			(island_removal_mode 0)
		)
		(polygon
			(pts
				(xy 14.560042 -293.166546) (xy 14.560042 -292.722808) (xy 16.885158 -292.722808) (xy 16.885158 -293.166546)
			)
		)
	)
	(zone
		(layer "F.Cu")
		(hatch none 0.5)
		(connect_pads
			(clearance 0)
		)
		(min_thickness 0.25)
		(keepout
			(tracks not_allowed)
			(vias allowed)
			(pads allowed)
			(copperpour not_allowed)
			(footprints allowed)
		)
		(placement
			(enabled no)
			(sheetname "")
		)
		(fill
			(thermal_gap 0.5)
			(thermal_bridge_width 0.5)
			(island_removal_mode 0)
		)
		(polygon
			(pts
				(xy 236.68228 -251.143008) (xy 236.68228 -249.486928) (xy 236.92358 -249.486928) (xy 236.92358 -251.143008)
			)
		)
	)
	(zone
		(layer "F.Cu")
		(hatch none 0.5)
		(connect_pads
			(clearance 0)
		)
		(min_thickness 0.25)
		(keepout
			(tracks not_allowed)
			(vias allowed)
			(pads allowed)
			(copperpour not_allowed)
			(footprints allowed)
		)
		(placement
			(enabled no)
			(sheetname "")
		)
		(fill
			(thermal_gap 0.5)
			(thermal_bridge_width 0.5)
			(island_removal_mode 0)
		)
		(polygon
			(pts
				(arc
					(start 338.959698 -206.024988)
					(mid 336.864706 -208.11998)
					(end 334.769714 -206.024988)
				)
				(arc
					(start 334.769714 -206.024988)
					(mid 336.864706 -203.929996)
					(end 338.959698 -206.024988)
				)
			)
		)
	)
	(zone
		(layer "F.Cu")
		(hatch none 0.5)
		(connect_pads
			(clearance 0)
		)
		(min_thickness 0.25)
		(keepout
			(tracks allowed)
			(vias allowed)
			(pads allowed)
			(copperpour allowed)
			(footprints not_allowed)
		)
		(placement
			(enabled no)
			(sheetname "")
		)
		(fill
			(thermal_gap 0.5)
			(thermal_bridge_width 0.5)
			(island_removal_mode 0)
		)
		(polygon
			(pts
				(arc
					(start 450.349874 -435.600094)
					(mid 448.799966 -437.150002)
					(end 447.250058 -435.600094)
				)
				(arc
					(start 447.250058 -435.600094)
					(mid 448.799966 -434.050186)
					(end 450.349874 -435.600094)
				)
			)
		)
	)
	(zone
		(layer "F.Cu")
		(hatch none 0.5)
		(connect_pads
			(clearance 0)
		)
		(min_thickness 0.25)
		(keepout
			(tracks allowed)
			(vias allowed)
			(pads allowed)
			(copperpour allowed)
			(footprints allowed)
		)
		(placement
			(enabled no)
			(sheetname "")
		)
		(fill
			(thermal_gap 0.5)
			(thermal_bridge_width 0.5)
			(island_removal_mode 0)
		)
		(polygon
			(pts
				(xy 331.092302 -404.802594) (xy 331.092302 -399.959576) (xy 332.976728 -399.959576) (xy 332.976728 -404.802594)
			)
		)
	)
	(zone
		(layer "F.Cu")
		(hatch none 0.5)
		(connect_pads
			(clearance 0)
		)
		(min_thickness 0.25)
		(keepout
			(tracks allowed)
			(vias allowed)
			(pads allowed)
			(copperpour allowed)
			(footprints allowed)
		)
		(placement
			(enabled no)
			(sheetname "")
		)
		(fill
			(thermal_gap 0.5)
			(thermal_bridge_width 0.5)
			(island_removal_mode 0)
		)
		(polygon
			(pts
				(xy 424.919394 -284.556962) (xy 426.951394 -284.556962) (xy 426.951394 -284.328362) (xy 424.919394 -284.328362)
				(xy 424.788076 -284.328362) (xy 424.762168 -284.328362) (xy 424.762168 -284.556962) (xy 424.788076 -284.556962)
			)
		)
	)
	(zone
		(layer "F.Cu")
		(hatch none 0.5)
		(connect_pads
			(clearance 0)
		)
		(min_thickness 0.25)
		(keepout
			(tracks allowed)
			(vias allowed)
			(pads allowed)
			(copperpour allowed)
			(footprints allowed)
		)
		(placement
			(enabled no)
			(sheetname "")
		)
		(fill
			(thermal_gap 0.5)
			(thermal_bridge_width 0.5)
			(island_removal_mode 0)
		)
		(polygon
			(pts
				(xy 161.891726 -265.004804) (xy 161.891726 -264.776204) (xy 163.923726 -264.776204) (xy 163.923726 -265.004804)
			)
		)
	)
	(zone
		(layer "F.Cu")
		(hatch none 0.5)
		(connect_pads
			(clearance 0)
		)
		(min_thickness 0.25)
		(keepout
			(tracks allowed)
			(vias allowed)
			(pads allowed)
			(copperpour allowed)
			(footprints allowed)
		)
		(placement
			(enabled no)
			(sheetname "")
		)
		(fill
			(thermal_gap 0.5)
			(thermal_bridge_width 0.5)
			(island_removal_mode 0)
		)
		(polygon
			(pts
				(xy 274.143978 -222.616522) (xy 274.143978 -222.172784) (xy 276.469094 -222.172784) (xy 276.469094 -222.616522)
			)
		)
	)
	(zone
		(layer "F.Cu")
		(hatch none 0.5)
		(connect_pads
			(clearance 0)
		)
		(min_thickness 0.25)
		(keepout
			(tracks allowed)
			(vias allowed)
			(pads allowed)
			(copperpour allowed)
			(footprints allowed)
		)
		(placement
			(enabled no)
			(sheetname "")
		)
		(fill
			(thermal_gap 0.5)
			(thermal_bridge_width 0.5)
			(island_removal_mode 0)
		)
		(polygon
			(pts
				(xy 339.415374 -336.996786) (xy 335.879694 -336.996786) (xy 335.879694 -334.913986) (xy 339.415374 -334.913986)
			)
		)
	)
	(zone
		(layer "F.Cu")
		(hatch none 0.5)
		(connect_pads
			(clearance 0)
		)
		(min_thickness 0.25)
		(keepout
			(tracks allowed)
			(vias allowed)
			(pads allowed)
			(copperpour allowed)
			(footprints allowed)
		)
		(placement
			(enabled no)
			(sheetname "")
		)
		(fill
			(thermal_gap 0.5)
			(thermal_bridge_width 0.5)
			(island_removal_mode 0)
		)
		(polygon
			(pts
				(xy 333.7052 -285.798768) (xy 333.99222 -285.798768) (xy 334.0227 -285.768288) (xy 334.0227 -285.140908)
				(xy 333.93634 -285.054548) (xy 333.74838 -285.054548) (xy 333.67472 -285.128208) (xy 333.67472 -285.768288)
			)
		)
	)
	(zone
		(layer "F.Cu")
		(hatch none 0.5)
		(connect_pads
			(clearance 0)
		)
		(min_thickness 0.25)
		(keepout
			(tracks allowed)
			(vias allowed)
			(pads allowed)
			(copperpour allowed)
			(footprints allowed)
		)
		(placement
			(enabled no)
			(sheetname "")
		)
		(fill
			(thermal_gap 0.5)
			(thermal_bridge_width 0.5)
			(island_removal_mode 0)
		)
		(polygon
			(pts
				(xy 442.21781 -269.028672) (xy 442.21781 -269.265908) (xy 442.355732 -269.265908) (xy 442.398912 -269.309088)
				(xy 442.398912 -269.44193) (xy 442.398912 -269.745968) (xy 442.326268 -269.818612) (xy 439.786014 -269.818612)
				(xy 439.64479 -269.677388) (xy 439.64479 -269.480284) (xy 439.726324 -269.39875) (xy 439.726324 -269.026386)
				(xy 439.726324 -268.435328) (xy 442.21781 -268.435328)
			)
		)
	)
	(zone
		(layer "F.Cu")
		(hatch none 0.5)
		(connect_pads
			(clearance 0)
		)
		(min_thickness 0.25)
		(keepout
			(tracks allowed)
			(vias allowed)
			(pads allowed)
			(copperpour allowed)
			(footprints allowed)
		)
		(placement
			(enabled no)
			(sheetname "")
		)
		(fill
			(thermal_gap 0.5)
			(thermal_bridge_width 0.5)
			(island_removal_mode 0)
		)
		(polygon
			(pts
				(xy 116.3955 -339.151468) (xy 116.3955 -334.472788) (xy 123.19508 -334.472788) (xy 123.19508 -339.151468)
			)
		)
	)
	(zone
		(layer "F.Cu")
		(hatch none 0.5)
		(connect_pads
			(clearance 0)
		)
		(min_thickness 0.25)
		(keepout
			(tracks allowed)
			(vias allowed)
			(pads allowed)
			(copperpour allowed)
			(footprints allowed)
		)
		(placement
			(enabled no)
			(sheetname "")
		)
		(fill
			(thermal_gap 0.5)
			(thermal_bridge_width 0.5)
			(island_removal_mode 0)
		)
		(polygon
			(pts
				(xy 161.891726 -274.976336) (xy 163.923726 -274.976336) (xy 163.923726 -274.978622) (xy 164.077396 -274.978622)
				(xy 164.077396 -275.768562) (xy 161.670746 -275.768562) (xy 161.410904 -275.768562) (xy 161.4043 -275.768562)
				(xy 161.4043 -275.291804) (xy 161.528506 -275.291804) (xy 161.528506 -274.976336) (xy 161.567114 -274.976336)
				(xy 161.611056 -274.976336) (xy 161.708592 -274.976336) (xy 161.755582 -274.976336)
			)
		)
	)
	(zone
		(layer "F.Cu")
		(hatch none 0.5)
		(connect_pads
			(clearance 0)
		)
		(min_thickness 0.25)
		(keepout
			(tracks allowed)
			(vias allowed)
			(pads allowed)
			(copperpour allowed)
			(footprints allowed)
		)
		(placement
			(enabled no)
			(sheetname "")
		)
		(fill
			(thermal_gap 0.5)
			(thermal_bridge_width 0.5)
			(island_removal_mode 0)
		)
		(polygon
			(pts
				(xy 424.919394 -209.75701) (xy 426.951394 -209.75701) (xy 426.951394 -209.52841) (xy 424.919394 -209.52841)
				(xy 424.788076 -209.52841) (xy 424.762168 -209.52841) (xy 424.762168 -209.75701) (xy 424.788076 -209.75701)
			)
		)
	)
	(zone
		(layer "F.Cu")
		(hatch none 0.5)
		(connect_pads
			(clearance 0)
		)
		(min_thickness 0.25)
		(keepout
			(tracks allowed)
			(vias allowed)
			(pads allowed)
			(copperpour allowed)
			(footprints allowed)
		)
		(placement
			(enabled no)
			(sheetname "")
		)
		(fill
			(thermal_gap 0.5)
			(thermal_bridge_width 0.5)
			(island_removal_mode 0)
		)
		(polygon
			(pts
				(xy 464.35264 -383.263648) (xy 464.35264 -382.156208) (xy 466.28304 -382.156208) (xy 466.28304 -383.263648)
			)
		)
	)
	(zone
		(layer "F.Cu")
		(hatch none 0.5)
		(connect_pads
			(clearance 0)
		)
		(min_thickness 0.25)
		(keepout
			(tracks allowed)
			(vias allowed)
			(pads allowed)
			(copperpour allowed)
			(footprints allowed)
		)
		(placement
			(enabled no)
			(sheetname "")
		)
		(fill
			(thermal_gap 0.5)
			(thermal_bridge_width 0.5)
			(island_removal_mode 0)
		)
		(polygon
			(pts
				(xy 382.08458 -75.535028) (xy 382.08458 -78.722728) (xy 383.00914 -79.647288) (xy 384.52298 -79.647288)
				(xy 385.20878 -78.961488) (xy 385.20878 -77.099668) (xy 385.14782 -77.038708) (xy 385.41198 -76.774548)
				(xy 391.17016 -76.774548) (xy 392.2395 -77.843888) (xy 392.91006 -77.843888) (xy 393.46378 -77.290168)
				(xy 393.46378 -75.044808) (xy 391.60196 -73.182988) (xy 384.43662 -73.182988)
			)
		)
	)
	(zone
		(layer "F.Cu")
		(hatch none 0.5)
		(connect_pads
			(clearance 0)
		)
		(min_thickness 0.25)
		(keepout
			(tracks allowed)
			(vias allowed)
			(pads allowed)
			(copperpour allowed)
			(footprints allowed)
		)
		(placement
			(enabled no)
			(sheetname "")
		)
		(fill
			(thermal_gap 0.5)
			(thermal_bridge_width 0.5)
			(island_removal_mode 0)
		)
		(polygon
			(pts
				(xy 85.2805 -283.324808) (xy 85.56752 -283.324808) (xy 85.598 -283.294328) (xy 85.598 -282.666948)
				(xy 85.51164 -282.580588) (xy 85.32368 -282.580588) (xy 85.25002 -282.654248) (xy 85.25002 -283.294328)
			)
		)
	)
	(zone
		(layer "F.Cu")
		(hatch none 0.5)
		(connect_pads
			(clearance 0)
		)
		(min_thickness 0.25)
		(keepout
			(tracks allowed)
			(vias allowed)
			(pads allowed)
			(copperpour allowed)
			(footprints allowed)
		)
		(placement
			(enabled no)
			(sheetname "")
		)
		(fill
			(thermal_gap 0.5)
			(thermal_bridge_width 0.5)
			(island_removal_mode 0)
		)
		(polygon
			(pts
				(xy 292.67531 -296.56659) (xy 292.67531 -296.122852) (xy 295.000426 -296.122852) (xy 295.000426 -296.56659)
			)
		)
	)
	(zone
		(layer "F.Cu")
		(hatch none 0.5)
		(connect_pads
			(clearance 0)
		)
		(min_thickness 0.25)
		(keepout
			(tracks allowed)
			(vias allowed)
			(pads allowed)
			(copperpour allowed)
			(footprints allowed)
		)
		(placement
			(enabled no)
			(sheetname "")
		)
		(fill
			(thermal_gap 0.5)
			(thermal_bridge_width 0.5)
			(island_removal_mode 0)
		)
		(polygon
			(pts
				(xy 428.363126 -293.05504) (xy 428.363126 -292.82644) (xy 430.395126 -292.82644) (xy 430.395126 -293.05504)
			)
		)
	)
	(zone
		(layer "F.Cu")
		(hatch none 0.5)
		(connect_pads
			(clearance 0)
		)
		(min_thickness 0.25)
		(keepout
			(tracks allowed)
			(vias allowed)
			(pads allowed)
			(copperpour allowed)
			(footprints not_allowed)
		)
		(placement
			(enabled no)
			(sheetname "")
		)
		(fill
			(thermal_gap 0.5)
			(thermal_bridge_width 0.5)
			(island_removal_mode 0)
		)
		(polygon
			(pts
				(arc
					(start 361.359958 -431.360072)
					(mid 359.774998 -432.945032)
					(end 358.190038 -431.360072)
				)
				(arc
					(start 358.190038 -431.360072)
					(mid 359.774998 -429.775112)
					(end 361.359958 -431.360072)
				)
			)
		)
	)
	(zone
		(layer "F.Cu")
		(hatch none 0.5)
		(connect_pads
			(clearance 0)
		)
		(min_thickness 0.25)
		(keepout
			(tracks allowed)
			(vias allowed)
			(pads allowed)
			(copperpour allowed)
			(footprints allowed)
		)
		(placement
			(enabled no)
			(sheetname "")
		)
		(fill
			(thermal_gap 0.5)
			(thermal_bridge_width 0.5)
			(island_removal_mode 0)
		)
		(polygon
			(pts
				(xy 163.934902 -276.056852) (xy 161.902902 -276.056852) (xy 161.902902 -276.054566) (xy 161.724086 -276.054566)
				(xy 161.53384 -276.054566) (xy 161.53384 -275.77415) (xy 161.4043 -275.77415) (xy 161.4043 -275.264626)
				(xy 161.615628 -275.264626) (xy 164.027104 -275.264626) (xy 164.077396 -275.264626) (xy 164.077396 -275.280628)
				(xy 164.077396 -276.056852) (xy 164.071046 -276.056852)
			)
		)
	)
	(zone
		(layer "F.Cu")
		(hatch none 0.5)
		(connect_pads
			(clearance 0)
		)
		(min_thickness 0.25)
		(keepout
			(tracks allowed)
			(vias allowed)
			(pads allowed)
			(copperpour allowed)
			(footprints allowed)
		)
		(placement
			(enabled no)
			(sheetname "")
		)
		(fill
			(thermal_gap 0.5)
			(thermal_bridge_width 0.5)
			(island_removal_mode 0)
		)
		(polygon
			(pts
				(xy 207.154526 -280.076402) (xy 209.186526 -280.076402) (xy 209.186526 -280.305002) (xy 207.154526 -280.305002)
				(xy 207.018382 -280.305002) (xy 206.971392 -280.305002) (xy 206.971392 -280.076402) (xy 207.018382 -280.076402)
			)
		)
	)
	(zone
		(layer "F.Cu")
		(hatch none 0.5)
		(connect_pads
			(clearance 0)
		)
		(min_thickness 0.25)
		(keepout
			(tracks allowed)
			(vias allowed)
			(pads allowed)
			(copperpour allowed)
			(footprints allowed)
		)
		(placement
			(enabled no)
			(sheetname "")
		)
		(fill
			(thermal_gap 0.5)
			(thermal_bridge_width 0.5)
			(island_removal_mode 0)
		)
		(polygon
			(pts
				(xy 26.20391 -210.716622) (xy 26.20391 -210.272884) (xy 28.529026 -210.272884) (xy 28.529026 -210.716622)
			)
		)
	)
	(zone
		(layer "F.Cu")
		(hatch none 0.5)
		(connect_pads
			(clearance 0)
		)
		(min_thickness 0.25)
		(keepout
			(tracks allowed)
			(vias allowed)
			(pads allowed)
			(copperpour allowed)
			(footprints allowed)
		)
		(placement
			(enabled no)
			(sheetname "")
		)
		(fill
			(thermal_gap 0.5)
			(thermal_bridge_width 0.5)
			(island_removal_mode 0)
		)
		(polygon
			(pts
				(xy 153.393648 -404.802594) (xy 153.393648 -399.959576) (xy 155.278074 -399.959576) (xy 155.278074 -404.802594)
			)
		)
	)
	(zone
		(layer "F.Cu")
		(hatch none 0.5)
		(connect_pads
			(clearance 0)
		)
		(min_thickness 0.25)
		(keepout
			(tracks allowed)
			(vias allowed)
			(pads allowed)
			(copperpour allowed)
			(footprints allowed)
		)
		(placement
			(enabled no)
			(sheetname "")
		)
		(fill
			(thermal_gap 0.5)
			(thermal_bridge_width 0.5)
			(island_removal_mode 0)
		)
		(polygon
			(pts
				(xy 56.37911 -299.116496) (xy 56.37911 -298.672758) (xy 58.704226 -298.672758) (xy 58.704226 -299.116496)
			)
		)
	)
	(zone
		(layer "F.Cu")
		(hatch none 0.5)
		(connect_pads
			(clearance 0)
		)
		(min_thickness 0.25)
		(keepout
			(tracks allowed)
			(vias allowed)
			(pads allowed)
			(copperpour allowed)
			(footprints allowed)
		)
		(placement
			(enabled no)
			(sheetname "")
		)
		(fill
			(thermal_gap 0.5)
			(thermal_bridge_width 0.5)
			(island_removal_mode 0)
		)
		(polygon
			(pts
				(xy 112.08512 -117.831108) (xy 112.08512 -115.217448) (xy 117.03812 -115.217448) (xy 117.03812 -117.831108)
			)
		)
	)
	(zone
		(layer "F.Cu")
		(hatch none 0.5)
		(connect_pads
			(clearance 0)
		)
		(min_thickness 0.25)
		(keepout
			(tracks allowed)
			(vias allowed)
			(pads allowed)
			(copperpour allowed)
			(footprints not_allowed)
		)
		(placement
			(enabled no)
			(sheetname "")
		)
		(fill
			(thermal_gap 0.5)
			(thermal_bridge_width 0.5)
			(island_removal_mode 0)
		)
		(polygon
			(pts
				(xy 2.999994 -91.764358) (xy 221.860872 -91.764358) (xy 221.860872 -82.764376) (xy 189.362334 -82.761074)
				(xy 189.361826 -87.281258) (xy 168.361868 -87.278972) (xy 168.362122 -82.774282) (xy 55.558944 -82.762598)
				(xy 55.558436 -87.267288) (xy 34.56178 -87.265002) (xy 34.562288 -82.774282) (xy 2.999994 -82.77098)
			)
		)
	)
	(zone
		(layer "F.Cu")
		(hatch none 0.5)
		(connect_pads
			(clearance 0)
		)
		(min_thickness 0.25)
		(keepout
			(tracks allowed)
			(vias allowed)
			(pads allowed)
			(copperpour allowed)
			(footprints allowed)
		)
		(placement
			(enabled no)
			(sheetname "")
		)
		(fill
			(thermal_gap 0.5)
			(thermal_bridge_width 0.5)
			(island_removal_mode 0)
		)
		(polygon
			(pts
				(xy 210.598258 -211.455) (xy 210.598258 -211.2264) (xy 212.630258 -211.2264) (xy 212.630258 -211.455)
			)
		)
	)
	(zone
		(layer "F.Cu")
		(hatch none 0.5)
		(connect_pads
			(clearance 0)
		)
		(min_thickness 0.25)
		(keepout
			(tracks allowed)
			(vias allowed)
			(pads allowed)
			(copperpour allowed)
			(footprints allowed)
		)
		(placement
			(enabled no)
			(sheetname "")
		)
		(fill
			(thermal_gap 0.5)
			(thermal_bridge_width 0.5)
			(island_removal_mode 0)
		)
		(polygon
			(pts
				(xy 428.363126 -272.65503) (xy 428.363126 -272.42643) (xy 430.395126 -272.42643) (xy 430.395126 -272.65503)
			)
		)
	)
	(zone
		(layer "F.Cu")
		(hatch none 0.5)
		(connect_pads
			(clearance 0)
		)
		(min_thickness 0.25)
		(keepout
			(tracks allowed)
			(vias allowed)
			(pads allowed)
			(copperpour allowed)
			(footprints allowed)
		)
		(placement
			(enabled no)
			(sheetname "")
		)
		(fill
			(thermal_gap 0.5)
			(thermal_bridge_width 0.5)
			(island_removal_mode 0)
		)
		(polygon
			(pts
				(xy 26.20391 -270.622776) (xy 28.529026 -270.622776) (xy 28.603194 -270.622776) (xy 28.603194 -271.53489)
				(xy 26.082498 -271.53489) (xy 26.082498 -270.622776)
			)
		)
	)
	(zone
		(layer "F.Cu")
		(hatch none 0.5)
		(connect_pads
			(clearance 0)
		)
		(min_thickness 0.25)
		(keepout
			(tracks allowed)
			(vias allowed)
			(pads allowed)
			(copperpour allowed)
			(footprints allowed)
		)
		(placement
			(enabled no)
			(sheetname "")
		)
		(fill
			(thermal_gap 0.5)
			(thermal_bridge_width 0.5)
			(island_removal_mode 0)
		)
		(polygon
			(pts
				(xy 274.143978 -234.922822) (xy 276.469094 -234.922822) (xy 276.53869 -234.922822) (xy 276.53869 -235.848906)
				(xy 274.009866 -235.848906) (xy 274.009866 -234.922822)
			)
		)
	)
	(zone
		(layer "F.Cu")
		(hatch none 0.5)
		(connect_pads
			(clearance 0)
		)
		(min_thickness 0.25)
		(keepout
			(tracks allowed)
			(vias allowed)
			(pads allowed)
			(copperpour allowed)
			(footprints allowed)
		)
		(placement
			(enabled no)
			(sheetname "")
		)
		(fill
			(thermal_gap 0.5)
			(thermal_bridge_width 0.5)
			(island_removal_mode 0)
		)
		(polygon
			(pts
				(xy 26.20391 -276.572726) (xy 28.529026 -276.572726) (xy 28.594812 -276.572726) (xy 28.594812 -277.460456)
				(xy 26.070052 -277.460456) (xy 26.070052 -276.572726)
			)
		)
	)
	(zone
		(layer "F.Cu")
		(hatch none 0.5)
		(connect_pads
			(clearance 0)
		)
		(min_thickness 0.25)
		(keepout
			(tracks allowed)
			(vias allowed)
			(pads allowed)
			(copperpour allowed)
			(footprints allowed)
		)
		(placement
			(enabled no)
			(sheetname "")
		)
		(fill
			(thermal_gap 0.5)
			(thermal_bridge_width 0.5)
			(island_removal_mode 0)
		)
		(polygon
			(pts
				(xy 428.363126 -196.154802) (xy 428.363126 -195.926202) (xy 430.395126 -195.926202) (xy 430.395126 -196.154802)
			)
		)
	)
	(zone
		(layer "F.Cu")
		(hatch none 0.5)
		(connect_pads
			(clearance 0)
		)
		(min_thickness 0.25)
		(keepout
			(tracks not_allowed)
			(vias allowed)
			(pads allowed)
			(copperpour not_allowed)
			(footprints allowed)
		)
		(placement
			(enabled no)
			(sheetname "")
		)
		(fill
			(thermal_gap 0.5)
			(thermal_bridge_width 0.5)
			(island_removal_mode 0)
		)
		(polygon
			(pts
				(xy 65.469008 -9.0424) (xy 65.644268 -9.0424) (xy 65.672208 -9.01446) (xy 65.672208 -7.62) (xy 65.649348 -7.59714)
				(xy 65.479168 -7.59714) (xy 65.458848 -7.61746) (xy 65.458848 -9.03224)
			)
		)
	)
	(zone
		(layer "F.Cu")
		(hatch none 0.5)
		(connect_pads
			(clearance 0)
		)
		(min_thickness 0.25)
		(keepout
			(tracks allowed)
			(vias allowed)
			(pads allowed)
			(copperpour allowed)
			(footprints allowed)
		)
		(placement
			(enabled no)
			(sheetname "")
		)
		(fill
			(thermal_gap 0.5)
			(thermal_bridge_width 0.5)
			(island_removal_mode 0)
		)
		(polygon
			(pts
				(xy 78.44536 -335.478628) (xy 84.443062 -335.478628) (xy 85.442298 -334.479392) (xy 85.442298 -328.35596)
				(xy 86.161626 -327.636632) (xy 91.495626 -327.636632) (xy 91.749626 -327.382632) (xy 91.749626 -326.112632)
				(xy 91.564968 -325.927974) (xy 85.617812 -325.927974) (xy 83.875626 -327.67016) (xy 83.875626 -333.191612)
				(xy 82.96021 -334.107028) (xy 78.43266 -334.107028) (xy 78.41996 -334.119728) (xy 78.41996 -335.453228)
			)
		)
	)
	(zone
		(layer "F.Cu")
		(hatch none 0.5)
		(connect_pads
			(clearance 0)
		)
		(min_thickness 0.25)
		(keepout
			(tracks not_allowed)
			(vias allowed)
			(pads allowed)
			(copperpour not_allowed)
			(footprints allowed)
		)
		(placement
			(enabled no)
			(sheetname "")
		)
		(fill
			(thermal_gap 0.5)
			(thermal_bridge_width 0.5)
			(island_removal_mode 0)
		)
		(polygon
			(pts
				(xy 286.741616 -364.373668) (xy 286.983932 -364.373668) (xy 286.983932 -363.576108) (xy 286.741616 -363.576108)
			)
		)
	)
	(zone
		(layer "F.Cu")
		(hatch none 0.5)
		(connect_pads
			(clearance 0)
		)
		(min_thickness 0.25)
		(keepout
			(tracks allowed)
			(vias allowed)
			(pads allowed)
			(copperpour allowed)
			(footprints allowed)
		)
		(placement
			(enabled no)
			(sheetname "")
		)
		(fill
			(thermal_gap 0.5)
			(thermal_bridge_width 0.5)
			(island_removal_mode 0)
		)
		(polygon
			(pts
				(xy 136.05256 -288.219388) (xy 136.33958 -288.219388) (xy 136.37006 -288.188908) (xy 136.37006 -287.561528)
				(xy 136.2837 -287.475168) (xy 136.09574 -287.475168) (xy 136.02208 -287.548828) (xy 136.02208 -288.188908)
			)
		)
	)
	(zone
		(layer "F.Cu")
		(hatch none 0.5)
		(connect_pads
			(clearance 0)
		)
		(min_thickness 0.25)
		(keepout
			(tracks allowed)
			(vias allowed)
			(pads allowed)
			(copperpour allowed)
			(footprints not_allowed)
		)
		(placement
			(enabled no)
			(sheetname "")
		)
		(fill
			(thermal_gap 0.5)
			(thermal_bridge_width 0.5)
			(island_removal_mode 0)
		)
		(polygon
			(pts
				(xy 106.499914 -440.89193)
				(arc
					(start 106.499914 -430.308004)
					(mid 100.499726 -427.599819)
					(end 94.499938 -430.308766)
				)
				(xy 94.499938 -440.891168) (xy 94.588584 -440.989974) (xy 106.41203 -440.989974)
			)
		)
	)
	(zone
		(layer "F.Cu")
		(hatch none 0.5)
		(connect_pads
			(clearance 0)
		)
		(min_thickness 0.25)
		(keepout
			(tracks allowed)
			(vias allowed)
			(pads allowed)
			(copperpour allowed)
			(footprints allowed)
		)
		(placement
			(enabled no)
			(sheetname "")
		)
		(fill
			(thermal_gap 0.5)
			(thermal_bridge_width 0.5)
			(island_removal_mode 0)
		)
		(polygon
			(pts
				(xy 274.143978 -295.716452) (xy 274.143978 -295.272714) (xy 276.469094 -295.272714) (xy 276.469094 -295.716452)
			)
		)
	)
	(zone
		(layer "F.Cu")
		(hatch none 0.5)
		(connect_pads
			(clearance 0)
		)
		(min_thickness 0.25)
		(keepout
			(tracks allowed)
			(vias allowed)
			(pads allowed)
			(copperpour allowed)
			(footprints allowed)
		)
		(placement
			(enabled no)
			(sheetname "")
		)
		(fill
			(thermal_gap 0.5)
			(thermal_bridge_width 0.5)
			(island_removal_mode 0)
		)
		(polygon
			(pts
				(xy 56.37911 -308.46649) (xy 56.37911 -308.022752) (xy 58.704226 -308.022752) (xy 58.704226 -308.46649)
			)
		)
	)
	(zone
		(layer "F.Cu")
		(hatch none 0.5)
		(connect_pads
			(clearance 0)
		)
		(min_thickness 0.25)
		(keepout
			(tracks allowed)
			(vias allowed)
			(pads allowed)
			(copperpour allowed)
			(footprints allowed)
		)
		(placement
			(enabled no)
			(sheetname "")
		)
		(fill
			(thermal_gap 0.5)
			(thermal_bridge_width 0.5)
			(island_removal_mode 0)
		)
		(polygon
			(pts
				(xy 259.056378 -272.766536) (xy 259.056378 -272.322798) (xy 261.381494 -272.322798) (xy 261.381494 -272.766536)
			)
		)
	)
	(zone
		(layer "F.Cu")
		(hatch none 0.5)
		(connect_pads
			(clearance 0)
		)
		(min_thickness 0.25)
		(keepout
			(tracks allowed)
			(vias allowed)
			(pads allowed)
			(copperpour allowed)
			(footprints allowed)
		)
		(placement
			(enabled no)
			(sheetname "")
		)
		(fill
			(thermal_gap 0.5)
			(thermal_bridge_width 0.5)
			(island_removal_mode 0)
		)
		(polygon
			(pts
				(xy 385.77774 -220.111828) (xy 386.06476 -220.111828) (xy 386.09524 -220.081348) (xy 386.09524 -219.453968)
				(xy 386.00888 -219.367608) (xy 385.82092 -219.367608) (xy 385.74726 -219.441268) (xy 385.74726 -220.081348)
			)
		)
	)
	(zone
		(layer "F.Cu")
		(hatch none 0.5)
		(connect_pads
			(clearance 0)
		)
		(min_thickness 0.25)
		(keepout
			(tracks allowed)
			(vias allowed)
			(pads allowed)
			(copperpour allowed)
			(footprints allowed)
		)
		(placement
			(enabled no)
			(sheetname "")
		)
		(fill
			(thermal_gap 0.5)
			(thermal_bridge_width 0.5)
			(island_removal_mode 0)
		)
		(polygon
			(pts
				(xy 413.982916 -181.990746) (xy 417.988496 -181.990746) (xy 418.468556 -181.510686) (xy 418.468556 -179.445666)
				(xy 418.196776 -179.173886) (xy 416.342576 -179.173886) (xy 416.091116 -178.922426) (xy 416.091116 -177.002186)
				(xy 415.674556 -176.585626) (xy 414.183576 -176.585626) (xy 413.535876 -177.233326) (xy 413.535876 -181.543706)
			)
		)
	)
	(zone
		(layer "F.Cu")
		(hatch none 0.5)
		(connect_pads
			(clearance 0)
		)
		(min_thickness 0.25)
		(keepout
			(tracks allowed)
			(vias allowed)
			(pads allowed)
			(copperpour allowed)
			(footprints not_allowed)
		)
		(placement
			(enabled no)
			(sheetname "")
		)
		(fill
			(thermal_gap 0.5)
			(thermal_bridge_width 0.5)
			(island_removal_mode 0)
		)
		(polygon
			(pts
				(xy 221.939358 -374.753886) (xy 221.939866 -398.75587) (xy 249.879866 -398.75587) (xy 249.879866 -374.753886)
				(xy 244.879876 -374.753886) (xy 244.879876 -350.763586) (xy 256.124964 -350.763586) (xy 256.124964 -347.521784)
				(xy 248.630694 -347.521784) (xy 248.630694 -344.084656) (xy 223.169988 -344.084656) (xy 223.169988 -347.521784)
				(xy 215.674956 -347.521784) (xy 215.674956 -350.763586) (xy 226.939856 -350.763586) (xy 226.939856 -374.753886)
			)
		)
	)
	(zone
		(layer "F.Cu")
		(hatch none 0.5)
		(connect_pads
			(clearance 0)
		)
		(min_thickness 0.25)
		(keepout
			(tracks allowed)
			(vias allowed)
			(pads allowed)
			(copperpour allowed)
			(footprints allowed)
		)
		(placement
			(enabled no)
			(sheetname "")
		)
		(fill
			(thermal_gap 0.5)
			(thermal_bridge_width 0.5)
			(island_removal_mode 0)
		)
		(polygon
			(pts
				(xy 409.831794 -316.004956) (xy 409.831794 -315.776356) (xy 411.863794 -315.776356) (xy 411.863794 -316.004956)
			)
		)
	)
	(zone
		(layer "F.Cu")
		(hatch none 0.5)
		(connect_pads
			(clearance 0)
		)
		(min_thickness 0.25)
		(keepout
			(tracks not_allowed)
			(vias allowed)
			(pads allowed)
			(copperpour not_allowed)
			(footprints allowed)
		)
		(placement
			(enabled no)
			(sheetname "")
		)
		(fill
			(thermal_gap 0.5)
			(thermal_bridge_width 0.5)
			(island_removal_mode 0)
		)
		(polygon
			(pts
				(xy 78.632304 -345.461336) (xy 82.57794 -345.461336) (xy 82.57794 -345.395804) (xy 82.45856 -345.276424)
				(xy 81.020158 -345.276424) (xy 81.020158 -343.117424) (xy 83.176872 -343.117424) (xy 83.176872 -342.867742)
				(xy 80.8355 -342.867742) (xy 80.8355 -343.190068) (xy 80.72882 -343.190068) (xy 80.72882 -345.220798)
				(xy 78.87462 -345.220798) (xy 78.87462 -344.979752) (xy 78.632304 -344.979752)
			)
		)
	)
	(zone
		(layer "F.Cu")
		(hatch none 0.5)
		(connect_pads
			(clearance 0)
		)
		(min_thickness 0.25)
		(keepout
			(tracks allowed)
			(vias allowed)
			(pads allowed)
			(copperpour allowed)
			(footprints allowed)
		)
		(placement
			(enabled no)
			(sheetname "")
		)
		(fill
			(thermal_gap 0.5)
			(thermal_bridge_width 0.5)
			(island_removal_mode 0)
		)
		(polygon
			(pts
				(xy 307.76291 -230.266494) (xy 307.76291 -229.822756) (xy 310.088026 -229.822756) (xy 310.088026 -230.266494)
			)
		)
	)
	(zone
		(layer "F.Cu")
		(hatch none 0.5)
		(connect_pads
			(clearance 0)
		)
		(min_thickness 0.25)
		(keepout
			(tracks allowed)
			(vias allowed)
			(pads allowed)
			(copperpour allowed)
			(footprints allowed)
		)
		(placement
			(enabled no)
			(sheetname "")
		)
		(fill
			(thermal_gap 0.5)
			(thermal_bridge_width 0.5)
			(island_removal_mode 0)
		)
		(polygon
			(pts
				(xy 455.094594 -228.456998) (xy 457.126594 -228.456998) (xy 457.126594 -228.228398) (xy 455.094594 -228.228398)
				(xy 454.963276 -228.228398) (xy 454.937368 -228.228398) (xy 454.937368 -228.456998) (xy 454.963276 -228.456998)
			)
		)
	)
	(zone
		(layer "F.Cu")
		(hatch none 0.5)
		(connect_pads
			(clearance 0)
		)
		(min_thickness 0.25)
		(keepout
			(tracks allowed)
			(vias allowed)
			(pads allowed)
			(copperpour allowed)
			(footprints allowed)
		)
		(placement
			(enabled no)
			(sheetname "")
		)
		(fill
			(thermal_gap 0.5)
			(thermal_bridge_width 0.5)
			(island_removal_mode 0)
		)
		(polygon
			(pts
				(xy 236.21238 -396.443708) (xy 236.21238 -393.151868) (xy 239.55756 -393.151868) (xy 239.55756 -396.443708)
			)
		)
	)
	(zone
		(layer "F.Cu")
		(hatch none 0.5)
		(connect_pads
			(clearance 0)
		)
		(min_thickness 0.25)
		(keepout
			(tracks allowed)
			(vias allowed)
			(pads allowed)
			(copperpour allowed)
			(footprints allowed)
		)
		(placement
			(enabled no)
			(sheetname "")
		)
		(fill
			(thermal_gap 0.5)
			(thermal_bridge_width 0.5)
			(island_removal_mode 0)
		)
		(polygon
			(pts
				(xy 63.951612 -288.06648) (xy 63.951612 -287.622742) (xy 66.237612 -287.622742) (xy 66.237612 -288.06648)
			)
		)
	)
	(zone
		(layer "F.Cu")
		(hatch none 0.5)
		(connect_pads
			(clearance 0)
		)
		(min_thickness 0.25)
		(keepout
			(tracks allowed)
			(vias allowed)
			(pads allowed)
			(copperpour allowed)
			(footprints allowed)
		)
		(placement
			(enabled no)
			(sheetname "")
		)
		(fill
			(thermal_gap 0.5)
			(thermal_bridge_width 0.5)
			(island_removal_mode 0)
		)
		(polygon
			(pts
				(xy 212.3313 -395.072108) (xy 212.3313 -391.709148) (xy 215.60282 -391.709148) (xy 215.60282 -395.072108)
			)
		)
	)
	(zone
		(layer "F.Cu")
		(hatch none 0.5)
		(connect_pads
			(clearance 0)
		)
		(min_thickness 0.25)
		(keepout
			(tracks allowed)
			(vias allowed)
			(pads allowed)
			(copperpour allowed)
			(footprints allowed)
		)
		(placement
			(enabled no)
			(sheetname "")
		)
		(fill
			(thermal_gap 0.5)
			(thermal_bridge_width 0.5)
			(island_removal_mode 0)
		)
		(polygon
			(pts
				(xy 31.972758 -239.616488) (xy 29.647642 -239.616488) (xy 29.513022 -239.616488) (xy 29.513022 -238.667036)
				(xy 32.041592 -238.667036) (xy 32.041592 -239.616488)
			)
		)
	)
	(zone
		(layer "F.Cu")
		(hatch none 0.5)
		(connect_pads
			(clearance 0)
		)
		(min_thickness 0.25)
		(keepout
			(tracks allowed)
			(vias allowed)
			(pads allowed)
			(copperpour allowed)
			(footprints allowed)
		)
		(placement
			(enabled no)
			(sheetname "")
		)
		(fill
			(thermal_gap 0.5)
			(thermal_bridge_width 0.5)
			(island_removal_mode 0)
		)
		(polygon
			(pts
				(xy 405.731726 -196.154802) (xy 405.731726 -195.926202) (xy 407.763726 -195.926202) (xy 407.763726 -196.154802)
			)
		)
	)
	(zone
		(layer "F.Cu")
		(hatch none 0.5)
		(connect_pads
			(clearance 0)
		)
		(min_thickness 0.25)
		(keepout
			(tracks allowed)
			(vias allowed)
			(pads allowed)
			(copperpour allowed)
			(footprints allowed)
		)
		(placement
			(enabled no)
			(sheetname "")
		)
		(fill
			(thermal_gap 0.5)
			(thermal_bridge_width 0.5)
			(island_removal_mode 0)
		)
		(polygon
			(pts
				(xy 41.29151 -262.566658) (xy 41.29151 -262.12292) (xy 43.616626 -262.12292) (xy 43.616626 -262.566658)
			)
		)
	)
	(zone
		(layer "F.Cu")
		(hatch none 0.5)
		(connect_pads
			(clearance 0)
		)
		(min_thickness 0.25)
		(keepout
			(tracks allowed)
			(vias allowed)
			(pads allowed)
			(copperpour allowed)
			(footprints allowed)
		)
		(placement
			(enabled no)
			(sheetname "")
		)
		(fill
			(thermal_gap 0.5)
			(thermal_bridge_width 0.5)
			(island_removal_mode 0)
		)
		(polygon
			(pts
				(xy 445.15278 -9.180068) (xy 445.15278 -6.365748) (xy 447.5226 -6.365748) (xy 447.5226 -9.180068)
			)
		)
	)
	(zone
		(layer "F.Cu")
		(hatch none 0.5)
		(connect_pads
			(clearance 0)
		)
		(min_thickness 0.25)
		(keepout
			(tracks allowed)
			(vias allowed)
			(pads allowed)
			(copperpour allowed)
			(footprints allowed)
		)
		(placement
			(enabled no)
			(sheetname "")
		)
		(fill
			(thermal_gap 0.5)
			(thermal_bridge_width 0.5)
			(island_removal_mode 0)
		)
		(polygon
			(pts
				(xy 262.50011 -287.216596) (xy 262.50011 -286.772858) (xy 264.825226 -286.772858) (xy 264.825226 -287.216596)
			)
		)
	)
	(zone
		(layer "F.Cu")
		(hatch none 0.5)
		(connect_pads
			(clearance 0)
		)
		(min_thickness 0.25)
		(keepout
			(tracks allowed)
			(vias allowed)
			(pads allowed)
			(copperpour allowed)
			(footprints allowed)
		)
		(placement
			(enabled no)
			(sheetname "")
		)
		(fill
			(thermal_gap 0.5)
			(thermal_bridge_width 0.5)
			(island_removal_mode 0)
		)
		(polygon
			(pts
				(xy 157.791658 -311.755028) (xy 157.791658 -311.526428) (xy 159.823658 -311.526428) (xy 159.823658 -311.755028)
			)
		)
	)
	(zone
		(layer "F.Cu")
		(hatch none 0.5)
		(connect_pads
			(clearance 0)
		)
		(min_thickness 0.25)
		(keepout
			(tracks allowed)
			(vias allowed)
			(pads allowed)
			(copperpour allowed)
			(footprints allowed)
		)
		(placement
			(enabled no)
			(sheetname "")
		)
		(fill
			(thermal_gap 0.5)
			(thermal_bridge_width 0.5)
			(island_removal_mode 0)
		)
		(polygon
			(pts
				(xy 424.919394 -235.026454) (xy 426.951394 -235.026454) (xy 426.951394 -235.255054) (xy 424.919394 -235.255054)
				(xy 424.78325 -235.255054) (xy 424.73626 -235.255054) (xy 424.73626 -235.026454) (xy 424.78325 -235.026454)
			)
		)
	)
	(zone
		(layer "F.Cu")
		(hatch none 0.5)
		(connect_pads
			(clearance 0)
		)
		(min_thickness 0.25)
		(keepout
			(tracks allowed)
			(vias allowed)
			(pads allowed)
			(copperpour allowed)
			(footprints allowed)
		)
		(placement
			(enabled no)
			(sheetname "")
		)
		(fill
			(thermal_gap 0.5)
			(thermal_bridge_width 0.5)
			(island_removal_mode 0)
		)
		(polygon
			(pts
				(xy 59.913012 -244.716554) (xy 59.913012 -244.272816) (xy 62.072012 -244.272816) (xy 62.132718 -244.272816)
				(xy 62.132718 -244.716554) (xy 62.072012 -244.716554)
			)
		)
	)
	(zone
		(layer "F.Cu")
		(hatch none 0.5)
		(connect_pads
			(clearance 0)
		)
		(min_thickness 0.25)
		(keepout
			(tracks allowed)
			(vias allowed)
			(pads allowed)
			(copperpour allowed)
			(footprints allowed)
		)
		(placement
			(enabled no)
			(sheetname "")
		)
		(fill
			(thermal_gap 0.5)
			(thermal_bridge_width 0.5)
			(island_removal_mode 0)
		)
		(polygon
			(pts
				(xy 440.006994 -278.37638) (xy 442.038994 -278.37638) (xy 442.038994 -278.378666) (xy 442.21781 -278.378666)
				(xy 442.21781 -278.615902) (xy 442.355732 -278.615902) (xy 442.398912 -278.659082) (xy 442.398912 -278.791924)
				(xy 442.398912 -279.095962) (xy 442.326268 -279.168606) (xy 439.786014 -279.168606) (xy 439.64479 -279.027382)
				(xy 439.64479 -278.830278) (xy 439.726324 -278.748744) (xy 439.726324 -278.37638) (xy 439.82386 -278.37638)
				(xy 439.87085 -278.37638)
			)
		)
	)
	(zone
		(layer "F.Cu")
		(hatch none 0.5)
		(connect_pads
			(clearance 0)
		)
		(min_thickness 0.25)
		(keepout
			(tracks allowed)
			(vias allowed)
			(pads allowed)
			(copperpour allowed)
			(footprints allowed)
		)
		(placement
			(enabled no)
			(sheetname "")
		)
		(fill
			(thermal_gap 0.5)
			(thermal_bridge_width 0.5)
			(island_removal_mode 0)
		)
		(polygon
			(pts
				(xy 165.335458 -300.705012) (xy 165.335458 -300.476412) (xy 167.367458 -300.476412) (xy 167.367458 -300.705012)
			)
		)
	)
	(zone
		(layer "F.Cu")
		(hatch none 0.5)
		(connect_pads
			(clearance 0)
		)
		(min_thickness 0.25)
		(keepout
			(tracks allowed)
			(vias allowed)
			(pads allowed)
			(copperpour allowed)
			(footprints allowed)
		)
		(placement
			(enabled no)
			(sheetname "")
		)
		(fill
			(thermal_gap 0.5)
			(thermal_bridge_width 0.5)
			(island_removal_mode 0)
		)
		(polygon
			(pts
				(xy 26.20391 -286.366458) (xy 26.20391 -285.92272) (xy 28.529026 -285.92272) (xy 28.529026 -286.366458)
			)
		)
	)
	(zone
		(layer "F.Cu")
		(hatch none 0.5)
		(connect_pads
			(clearance 0)
		)
		(min_thickness 0.25)
		(keepout
			(tracks allowed)
			(vias allowed)
			(pads allowed)
			(copperpour allowed)
			(footprints allowed)
		)
		(placement
			(enabled no)
			(sheetname "")
		)
		(fill
			(thermal_gap 0.5)
			(thermal_bridge_width 0.5)
			(island_removal_mode 0)
		)
		(polygon
			(pts
				(xy 311.862978 -287.216596) (xy 311.862978 -286.772858) (xy 314.188094 -286.772858) (xy 314.188094 -287.216596)
			)
		)
	)
	(zone
		(layer "F.Cu")
		(hatch none 0.5)
		(connect_pads
			(clearance 0)
		)
		(min_thickness 0.25)
		(keepout
			(tracks allowed)
			(vias allowed)
			(pads allowed)
			(copperpour allowed)
			(footprints allowed)
		)
		(placement
			(enabled no)
			(sheetname "")
		)
		(fill
			(thermal_gap 0.5)
			(thermal_bridge_width 0.5)
			(island_removal_mode 0)
		)
		(polygon
			(pts
				(xy 445.493902 -239.507014) (xy 443.461902 -239.507014) (xy 443.461902 -239.504728) (xy 443.283086 -239.504728)
				(xy 443.283086 -239.267492) (xy 443.145164 -239.267492) (xy 443.101984 -239.224312) (xy 443.101984 -239.09147)
				(xy 443.101984 -238.787432) (xy 443.174628 -238.714788) (xy 445.714882 -238.714788) (xy 445.856106 -238.856012)
				(xy 445.856106 -239.053116) (xy 445.774572 -239.13465) (xy 445.774572 -239.507014) (xy 445.677036 -239.507014)
				(xy 445.630046 -239.507014)
			)
		)
	)
	(zone
		(layer "F.Cu")
		(hatch none 0.5)
		(connect_pads
			(clearance 0)
		)
		(min_thickness 0.25)
		(keepout
			(tracks allowed)
			(vias allowed)
			(pads allowed)
			(copperpour allowed)
			(footprints allowed)
		)
		(placement
			(enabled no)
			(sheetname "")
		)
		(fill
			(thermal_gap 0.5)
			(thermal_bridge_width 0.5)
			(island_removal_mode 0)
		)
		(polygon
			(pts
				(xy 151.676608 -53.216302) (xy 151.676608 -51.47564) (xy 153.592022 -51.47564) (xy 153.592022 -53.216302)
			)
		)
	)
	(zone
		(layer "F.Cu")
		(hatch none 0.5)
		(connect_pads
			(clearance 0)
		)
		(min_thickness 0.25)
		(keepout
			(tracks allowed)
			(vias allowed)
			(pads allowed)
			(copperpour allowed)
			(footprints allowed)
		)
		(placement
			(enabled no)
			(sheetname "")
		)
		(fill
			(thermal_gap 0.5)
			(thermal_bridge_width 0.5)
			(island_removal_mode 0)
		)
		(polygon
			(pts
				(xy 176.979326 -303.25695) (xy 179.011326 -303.25695) (xy 179.011326 -303.02835) (xy 176.979326 -303.02835)
				(xy 176.848008 -303.02835) (xy 176.8221 -303.02835) (xy 176.8221 -303.25695) (xy 176.848008 -303.25695)
			)
		)
	)
	(zone
		(layer "F.Cu")
		(hatch none 0.5)
		(connect_pads
			(clearance 0)
		)
		(min_thickness 0.25)
		(keepout
			(tracks allowed)
			(vias allowed)
			(pads allowed)
			(copperpour allowed)
			(footprints allowed)
		)
		(placement
			(enabled no)
			(sheetname "")
		)
		(fill
			(thermal_gap 0.5)
			(thermal_bridge_width 0.5)
			(island_removal_mode 0)
		)
		(polygon
			(pts
				(xy 195.510658 -269.254986) (xy 195.510658 -269.026386) (xy 197.542658 -269.026386) (xy 197.542658 -269.254986)
			)
		)
	)
	(zone
		(layer "F.Cu")
		(hatch none 0.5)
		(connect_pads
			(clearance 0)
		)
		(min_thickness 0.25)
		(keepout
			(tracks allowed)
			(vias allowed)
			(pads allowed)
			(copperpour allowed)
			(footprints allowed)
		)
		(placement
			(enabled no)
			(sheetname "")
		)
		(fill
			(thermal_gap 0.5)
			(thermal_bridge_width 0.5)
			(island_removal_mode 0)
		)
		(polygon
			(pts
				(xy 409.831794 -216.554812) (xy 409.831794 -216.326212) (xy 411.863794 -216.326212) (xy 411.863794 -216.554812)
			)
		)
	)
	(zone
		(layer "F.Cu")
		(hatch none 0.5)
		(connect_pads
			(clearance 0)
		)
		(min_thickness 0.25)
		(keepout
			(tracks allowed)
			(vias allowed)
			(pads allowed)
			(copperpour allowed)
			(footprints allowed)
		)
		(placement
			(enabled no)
			(sheetname "")
		)
		(fill
			(thermal_gap 0.5)
			(thermal_bridge_width 0.5)
			(island_removal_mode 0)
		)
		(polygon
			(pts
				(xy 351.155 -65.623948) (xy 351.155 -64.125348) (xy 350.34728 -64.125348) (xy 350.266 -64.206628)
				(xy 350.139 -64.333628) (xy 350.139 -65.496948) (xy 350.266 -65.623948)
			)
		)
	)
	(zone
		(layer "F.Cu")
		(hatch none 0.5)
		(connect_pads
			(clearance 0)
		)
		(min_thickness 0.25)
		(keepout
			(tracks allowed)
			(vias allowed)
			(pads allowed)
			(copperpour allowed)
			(footprints not_allowed)
		)
		(placement
			(enabled no)
			(sheetname "")
		)
		(fill
			(thermal_gap 0.5)
			(thermal_bridge_width 0.5)
			(island_removal_mode 0)
		)
		(polygon
			(pts
				(xy 226.44989 -46.999906) (xy 230.650034 -46.999906) (xy 230.650034 -41.999916) (xy 226.44989 -41.999916)
			)
		)
	)
	(zone
		(layer "F.Cu")
		(hatch none 0.5)
		(connect_pads
			(clearance 0)
		)
		(min_thickness 0.25)
		(keepout
			(tracks allowed)
			(vias allowed)
			(pads allowed)
			(copperpour allowed)
			(footprints allowed)
		)
		(placement
			(enabled no)
			(sheetname "")
		)
		(fill
			(thermal_gap 0.5)
			(thermal_bridge_width 0.5)
			(island_removal_mode 0)
		)
		(polygon
			(pts
				(xy 281.537156 -319.243456) (xy 281.537156 -316.881256) (xy 284.153356 -316.881256) (xy 284.153356 -319.243456)
			)
		)
	)
	(zone
		(layer "F.Cu")
		(hatch none 0.5)
		(connect_pads
			(clearance 0)
		)
		(min_thickness 0.25)
		(keepout
			(tracks allowed)
			(vias allowed)
			(pads allowed)
			(copperpour allowed)
			(footprints not_allowed)
		)
		(placement
			(enabled no)
			(sheetname "")
		)
		(fill
			(thermal_gap 0.5)
			(thermal_bridge_width 0.5)
			(island_removal_mode 0)
		)
		(polygon
			(pts
				(xy 117.54993 -440.989974) (xy 117.54993 -418.869876) (xy 106.499914 -418.869876) (xy 106.499914 -440.989974)
			)
		)
	)
	(zone
		(layer "F.Cu")
		(hatch none 0.5)
		(connect_pads
			(clearance 0)
		)
		(min_thickness 0.25)
		(keepout
			(tracks allowed)
			(vias allowed)
			(pads allowed)
			(copperpour allowed)
			(footprints allowed)
		)
		(placement
			(enabled no)
			(sheetname "")
		)
		(fill
			(thermal_gap 0.5)
			(thermal_bridge_width 0.5)
			(island_removal_mode 0)
		)
		(polygon
			(pts
				(xy 259.056378 -310.166512) (xy 259.056378 -309.722774) (xy 261.381494 -309.722774) (xy 261.381494 -310.166512)
			)
		)
	)
	(zone
		(layer "F.Cu")
		(hatch none 0.5)
		(connect_pads
			(clearance 0)
		)
		(min_thickness 0.25)
		(keepout
			(tracks allowed)
			(vias allowed)
			(pads allowed)
			(copperpour allowed)
			(footprints allowed)
		)
		(placement
			(enabled no)
			(sheetname "")
		)
		(fill
			(thermal_gap 0.5)
			(thermal_bridge_width 0.5)
			(island_removal_mode 0)
		)
		(polygon
			(pts
				(xy 210.598258 -276.904958) (xy 210.598258 -276.676358) (xy 212.630258 -276.676358) (xy 212.630258 -276.904958)
			)
		)
	)
	(zone
		(layer "F.Cu")
		(hatch none 0.5)
		(connect_pads
			(clearance 0)
		)
		(min_thickness 0.25)
		(keepout
			(tracks allowed)
			(vias allowed)
			(pads allowed)
			(copperpour allowed)
			(footprints not_allowed)
		)
		(placement
			(enabled no)
			(sheetname "")
		)
		(fill
			(thermal_gap 0.5)
			(thermal_bridge_width 0.5)
			(island_removal_mode 0)
		)
		(polygon
			(pts
				(xy 57.399936 -413.889952) (xy 74.30008 -413.889952) (xy 74.30008 -421.09009) (xy 91.300046 -421.09009)
				(xy 91.300046 -440.989974) (xy 94.499938 -440.989974) (xy 94.499938 -417.889944) (xy 77.499972 -417.889944)
				(xy 77.499972 -410.69006) (xy 54.200044 -410.69006) (xy 54.200044 -440.989974) (xy 57.399936 -440.989974)
			)
		)
	)
	(zone
		(layer "F.Cu")
		(hatch none 0.5)
		(connect_pads
			(clearance 0)
		)
		(min_thickness 0.25)
		(keepout
			(tracks allowed)
			(vias allowed)
			(pads allowed)
			(copperpour allowed)
			(footprints allowed)
		)
		(placement
			(enabled no)
			(sheetname "")
		)
		(fill
			(thermal_gap 0.5)
			(thermal_bridge_width 0.5)
			(island_removal_mode 0)
		)
		(polygon
			(pts
				(xy 440.006994 -263.076436) (xy 442.038994 -263.076436) (xy 442.038994 -263.305036) (xy 440.006994 -263.305036)
				(xy 439.84037 -263.305036) (xy 439.742834 -263.305036) (xy 439.742834 -263.076436) (xy 439.84037 -263.076436)
			)
		)
	)
	(zone
		(layer "F.Cu")
		(hatch none 0.5)
		(connect_pads
			(clearance 0)
		)
		(min_thickness 0.25)
		(keepout
			(tracks allowed)
			(vias allowed)
			(pads allowed)
			(copperpour allowed)
			(footprints allowed)
		)
		(placement
			(enabled no)
			(sheetname "")
		)
		(fill
			(thermal_gap 0.5)
			(thermal_bridge_width 0.5)
			(island_removal_mode 0)
		)
		(polygon
			(pts
				(xy 355.0158 -43.99534) (xy 355.0158 -42.94886) (xy 360.6292 -42.94886) (xy 360.6292 -43.99534)
			)
		)
	)
	(zone
		(layer "F.Cu")
		(hatch none 0.5)
		(connect_pads
			(clearance 0)
		)
		(min_thickness 0.25)
		(keepout
			(tracks allowed)
			(vias allowed)
			(pads allowed)
			(copperpour allowed)
			(footprints allowed)
		)
		(placement
			(enabled no)
			(sheetname "")
		)
		(fill
			(thermal_gap 0.5)
			(thermal_bridge_width 0.5)
			(island_removal_mode 0)
		)
		(polygon
			(pts
				(xy 59.913012 -245.566438) (xy 59.913012 -245.1227) (xy 62.072012 -245.1227) (xy 62.072012 -245.566438)
			)
		)
	)
	(zone
		(layer "F.Cu")
		(hatch none 0.5)
		(connect_pads
			(clearance 0)
		)
		(min_thickness 0.25)
		(keepout
			(tracks allowed)
			(vias allowed)
			(pads allowed)
			(copperpour allowed)
			(footprints allowed)
		)
		(placement
			(enabled no)
			(sheetname "")
		)
		(fill
			(thermal_gap 0.5)
			(thermal_bridge_width 0.5)
			(island_removal_mode 0)
		)
		(polygon
			(pts
				(xy 25.746202 -269.874238) (xy 28.939744 -269.874238) (xy 29.039566 -269.774416) (xy 29.039566 -268.789912)
				(xy 28.839922 -268.590268) (xy 25.500076 -268.590268) (xy 25.293828 -268.796516) (xy 25.293828 -269.421864)
			)
		)
	)
	(zone
		(layer "F.Cu")
		(hatch none 0.5)
		(connect_pads
			(clearance 0)
		)
		(min_thickness 0.25)
		(keepout
			(tracks allowed)
			(vias allowed)
			(pads allowed)
			(copperpour allowed)
			(footprints allowed)
		)
		(placement
			(enabled no)
			(sheetname "")
		)
		(fill
			(thermal_gap 0.5)
			(thermal_bridge_width 0.5)
			(island_removal_mode 0)
		)
		(polygon
			(pts
				(xy 443.450726 -264.15492) (xy 443.450726 -263.92632) (xy 445.482726 -263.92632) (xy 445.482726 -264.15492)
			)
		)
	)
	(zone
		(layer "F.Cu")
		(hatch none 0.5)
		(connect_pads
			(clearance 0)
		)
		(min_thickness 0.25)
		(keepout
			(tracks allowed)
			(vias allowed)
			(pads allowed)
			(copperpour allowed)
			(footprints allowed)
		)
		(placement
			(enabled no)
			(sheetname "")
		)
		(fill
			(thermal_gap 0.5)
			(thermal_bridge_width 0.5)
			(island_removal_mode 0)
		)
		(polygon
			(pts
				(xy 14.560042 -268.516608) (xy 14.560042 -268.07287) (xy 16.885158 -268.07287) (xy 16.885158 -268.516608)
			)
		)
	)
	(zone
		(layer "F.Cu")
		(hatch none 0.5)
		(connect_pads
			(clearance 0)
		)
		(min_thickness 0.25)
		(keepout
			(tracks allowed)
			(vias allowed)
			(pads allowed)
			(copperpour allowed)
			(footprints allowed)
		)
		(placement
			(enabled no)
			(sheetname "")
		)
		(fill
			(thermal_gap 0.5)
			(thermal_bridge_width 0.5)
			(island_removal_mode 0)
		)
		(polygon
			(pts
				(xy 11.11631 -280.416508) (xy 11.11631 -279.97277) (xy 13.441426 -279.97277) (xy 13.441426 -280.416508)
			)
		)
	)
	(zone
		(layer "F.Cu")
		(hatch none 0.5)
		(connect_pads
			(clearance 0)
		)
		(min_thickness 0.25)
		(keepout
			(tracks allowed)
			(vias allowed)
			(pads allowed)
			(copperpour allowed)
			(footprints allowed)
		)
		(placement
			(enabled no)
			(sheetname "")
		)
		(fill
			(thermal_gap 0.5)
			(thermal_bridge_width 0.5)
			(island_removal_mode 0)
		)
		(polygon
			(pts
				(xy 335.93532 -215.255348) (xy 336.22234 -215.255348) (xy 336.25282 -215.224868) (xy 336.25282 -214.597488)
				(xy 336.16646 -214.511128) (xy 335.9785 -214.511128) (xy 335.90484 -214.584788) (xy 335.90484 -215.224868)
			)
		)
	)
	(zone
		(layer "F.Cu")
		(hatch none 0.5)
		(connect_pads
			(clearance 0)
		)
		(min_thickness 0.25)
		(keepout
			(tracks allowed)
			(vias allowed)
			(pads allowed)
			(copperpour allowed)
			(footprints allowed)
		)
		(placement
			(enabled no)
			(sheetname "")
		)
		(fill
			(thermal_gap 0.5)
			(thermal_bridge_width 0.5)
			(island_removal_mode 0)
		)
		(polygon
			(pts
				(xy 455.094594 -293.906956) (xy 457.126594 -293.906956) (xy 457.126594 -293.678356) (xy 455.094594 -293.678356)
				(xy 454.963276 -293.678356) (xy 454.937368 -293.678356) (xy 454.937368 -293.906956) (xy 454.963276 -293.906956)
			)
		)
	)
	(zone
		(layer "F.Cu")
		(hatch none 0.5)
		(connect_pads
			(clearance 0)
		)
		(min_thickness 0.25)
		(keepout
			(tracks allowed)
			(vias allowed)
			(pads allowed)
			(copperpour allowed)
			(footprints allowed)
		)
		(placement
			(enabled no)
			(sheetname "")
		)
		(fill
			(thermal_gap 0.5)
			(thermal_bridge_width 0.5)
			(island_removal_mode 0)
		)
		(polygon
			(pts
				(xy 26.20391 -209.866484) (xy 26.20391 -209.422746) (xy 28.529026 -209.422746) (xy 28.529026 -209.866484)
			)
		)
	)
	(zone
		(layer "F.Cu")
		(hatch none 0.5)
		(connect_pads
			(clearance 0)
		)
		(min_thickness 0.25)
		(keepout
			(tracks allowed)
			(vias allowed)
			(pads allowed)
			(copperpour allowed)
			(footprints allowed)
		)
		(placement
			(enabled no)
			(sheetname "")
		)
		(fill
			(thermal_gap 0.5)
			(thermal_bridge_width 0.5)
			(island_removal_mode 0)
		)
		(polygon
			(pts
				(xy 396.818104 -410.948886) (xy 396.818104 -406.105868) (xy 398.70253 -406.105868) (xy 398.70253 -410.948886)
			)
		)
	)
	(zone
		(layer "F.Cu")
		(hatch none 0.5)
		(connect_pads
			(clearance 0)
		)
		(min_thickness 0.25)
		(keepout
			(tracks allowed)
			(vias allowed)
			(pads allowed)
			(copperpour allowed)
			(footprints allowed)
		)
		(placement
			(enabled no)
			(sheetname "")
		)
		(fill
			(thermal_gap 0.5)
			(thermal_bridge_width 0.5)
			(island_removal_mode 0)
		)
		(polygon
			(pts
				(xy 427.61408 -121.219468) (xy 427.61408 -125.712728) (xy 428.52848 -126.627128) (xy 431.58156 -126.627128)
				(xy 432.8541 -127.899668) (xy 432.8541 -128.646428) (xy 433.43068 -129.223008) (xy 433.86248 -129.223008)
				(xy 437.1086 -125.976888) (xy 437.1086 -121.074688) (xy 435.28234 -119.248428) (xy 429.58512 -119.248428)
			)
		)
	)
	(zone
		(layer "F.Cu")
		(hatch none 0.5)
		(connect_pads
			(clearance 0)
		)
		(min_thickness 0.25)
		(keepout
			(tracks allowed)
			(vias allowed)
			(pads allowed)
			(copperpour allowed)
			(footprints allowed)
		)
		(placement
			(enabled no)
			(sheetname "")
		)
		(fill
			(thermal_gap 0.5)
			(thermal_bridge_width 0.5)
			(island_removal_mode 0)
		)
		(polygon
			(pts
				(xy 59.822842 -226.016566) (xy 59.822842 -225.572828) (xy 62.147958 -225.572828) (xy 62.147958 -226.016566)
			)
		)
	)
	(zone
		(layer "F.Cu")
		(hatch none 0.5)
		(connect_pads
			(clearance 0)
		)
		(min_thickness 0.25)
		(keepout
			(tracks allowed)
			(vias allowed)
			(pads allowed)
			(copperpour allowed)
			(footprints allowed)
		)
		(placement
			(enabled no)
			(sheetname "")
		)
		(fill
			(thermal_gap 0.5)
			(thermal_bridge_width 0.5)
			(island_removal_mode 0)
		)
		(polygon
			(pts
				(xy 359.085896 -321.385184) (xy 359.085896 -319.083944) (xy 363.457236 -319.083944) (xy 363.457236 -321.385184)
			)
		)
	)
	(zone
		(layer "F.Cu")
		(hatch none 0.5)
		(connect_pads
			(clearance 0)
		)
		(min_thickness 0.25)
		(keepout
			(tracks allowed)
			(vias allowed)
			(pads allowed)
			(copperpour allowed)
			(footprints allowed)
		)
		(placement
			(enabled no)
			(sheetname "")
		)
		(fill
			(thermal_gap 0.5)
			(thermal_bridge_width 0.5)
			(island_removal_mode 0)
		)
		(polygon
			(pts
				(xy 304.319178 -304.216562) (xy 304.319178 -303.772824) (xy 306.644294 -303.772824) (xy 306.644294 -304.216562)
			)
		)
	)
	(zone
		(layer "F.Cu")
		(hatch none 0.5)
		(connect_pads
			(clearance 0)
		)
		(min_thickness 0.25)
		(keepout
			(tracks allowed)
			(vias allowed)
			(pads allowed)
			(copperpour allowed)
			(footprints allowed)
		)
		(placement
			(enabled no)
			(sheetname "")
		)
		(fill
			(thermal_gap 0.5)
			(thermal_bridge_width 0.5)
			(island_removal_mode 0)
		)
		(polygon
			(pts
				(xy 292.67531 -264.266426) (xy 292.67531 -263.822688) (xy 295.000426 -263.822688) (xy 295.000426 -264.266426)
			)
		)
	)
	(zone
		(layer "F.Cu")
		(hatch none 0.5)
		(connect_pads
			(clearance 0)
		)
		(min_thickness 0.25)
		(keepout
			(tracks allowed)
			(vias allowed)
			(pads allowed)
			(copperpour allowed)
			(footprints allowed)
		)
		(placement
			(enabled no)
			(sheetname "")
		)
		(fill
			(thermal_gap 0.5)
			(thermal_bridge_width 0.5)
			(island_removal_mode 0)
		)
		(polygon
			(pts
				(xy 440.006994 -195.926456) (xy 442.038994 -195.926456) (xy 442.038994 -196.155056) (xy 440.006994 -196.155056)
				(xy 439.87085 -196.155056) (xy 439.82386 -196.155056) (xy 439.82386 -195.926456) (xy 439.87085 -195.926456)
			)
		)
	)
	(zone
		(layer "F.Cu")
		(hatch none 0.5)
		(connect_pads
			(clearance 0)
		)
		(min_thickness 0.25)
		(keepout
			(tracks not_allowed)
			(vias allowed)
			(pads allowed)
			(copperpour not_allowed)
			(footprints allowed)
		)
		(placement
			(enabled no)
			(sheetname "")
		)
		(fill
			(thermal_gap 0.5)
			(thermal_bridge_width 0.5)
			(island_removal_mode 0)
		)
		(polygon
			(pts
				(xy 86.792816 -339.670644) (xy 90.77706 -339.670644) (xy 90.77706 -339.584792) (xy 90.678 -339.485732)
				(xy 89.18067 -339.485732) (xy 89.18067 -337.326732) (xy 91.337384 -337.326732) (xy 91.337384 -337.07705)
				(xy 88.99906 -337.07705) (xy 88.99906 -337.393788) (xy 88.889332 -337.393788) (xy 88.889332 -339.430106)
				(xy 87.035132 -339.430106) (xy 87.035132 -339.18906) (xy 86.792816 -339.18906)
			)
		)
	)
	(zone
		(layer "F.Cu")
		(hatch none 0.5)
		(connect_pads
			(clearance 0)
		)
		(min_thickness 0.25)
		(keepout
			(tracks allowed)
			(vias allowed)
			(pads allowed)
			(copperpour allowed)
			(footprints allowed)
		)
		(placement
			(enabled no)
			(sheetname "")
		)
		(fill
			(thermal_gap 0.5)
			(thermal_bridge_width 0.5)
			(island_removal_mode 0)
		)
		(polygon
			(pts
				(xy 33.597088 -319.243456) (xy 33.597088 -316.881256) (xy 36.213288 -316.881256) (xy 36.213288 -319.243456)
			)
		)
	)
	(zone
		(layer "F.Cu")
		(hatch none 0.5)
		(connect_pads
			(clearance 0)
		)
		(min_thickness 0.25)
		(keepout
			(tracks allowed)
			(vias allowed)
			(pads allowed)
			(copperpour allowed)
			(footprints allowed)
		)
		(placement
			(enabled no)
			(sheetname "")
		)
		(fill
			(thermal_gap 0.5)
			(thermal_bridge_width 0.5)
			(island_removal_mode 0)
		)
		(polygon
			(pts
				(xy 210.598258 -283.704792) (xy 210.598258 -283.476192) (xy 212.630258 -283.476192) (xy 212.630258 -283.704792)
			)
		)
	)
	(zone
		(layer "F.Cu")
		(hatch none 0.5)
		(connect_pads
			(clearance 0)
		)
		(min_thickness 0.25)
		(keepout
			(tracks allowed)
			(vias allowed)
			(pads allowed)
			(copperpour allowed)
			(footprints allowed)
		)
		(placement
			(enabled no)
			(sheetname "")
		)
		(fill
			(thermal_gap 0.5)
			(thermal_bridge_width 0.5)
			(island_removal_mode 0)
		)
		(polygon
			(pts
				(xy 161.891726 -210.604862) (xy 161.891726 -210.376262) (xy 163.923726 -210.376262) (xy 163.923726 -210.604862)
			)
		)
	)
	(zone
		(layer "F.Cu")
		(hatch none 0.5)
		(connect_pads
			(clearance 0)
		)
		(min_thickness 0.25)
		(keepout
			(tracks allowed)
			(vias allowed)
			(pads allowed)
			(copperpour allowed)
			(footprints allowed)
		)
		(placement
			(enabled no)
			(sheetname "")
		)
		(fill
			(thermal_gap 0.5)
			(thermal_bridge_width 0.5)
			(island_removal_mode 0)
		)
		(polygon
			(pts
				(xy 84.260182 -239.054386) (xy 84.463128 -239.257332) (xy 84.506308 -239.257332) (xy 84.950046 -238.813594)
				(xy 84.950046 -238.69142) (xy 84.81695 -238.558578) (xy 84.71281 -238.558578) (xy 84.260182 -239.011206)
			)
		)
	)
	(zone
		(layer "F.Cu")
		(hatch none 0.5)
		(connect_pads
			(clearance 0)
		)
		(min_thickness 0.25)
		(keepout
			(tracks allowed)
			(vias allowed)
			(pads allowed)
			(copperpour allowed)
			(footprints allowed)
		)
		(placement
			(enabled no)
			(sheetname "")
		)
		(fill
			(thermal_gap 0.5)
			(thermal_bridge_width 0.5)
			(island_removal_mode 0)
		)
		(polygon
			(pts
				(xy 195.510658 -198.704962) (xy 195.510658 -198.476362) (xy 197.542658 -198.476362) (xy 197.542658 -198.704962)
			)
		)
	)
	(zone
		(layer "F.Cu")
		(hatch none 0.5)
		(connect_pads
			(clearance 0)
		)
		(min_thickness 0.25)
		(keepout
			(tracks allowed)
			(vias allowed)
			(pads allowed)
			(copperpour allowed)
			(footprints allowed)
		)
		(placement
			(enabled no)
			(sheetname "")
		)
		(fill
			(thermal_gap 0.5)
			(thermal_bridge_width 0.5)
			(island_removal_mode 0)
		)
		(polygon
			(pts
				(xy 252.94336 -102.304088) (xy 252.94336 -96.942148) (xy 258.47294 -96.942148) (xy 258.47294 -102.304088)
			)
		)
	)
	(zone
		(layer "F.Cu")
		(hatch none 0.5)
		(connect_pads
			(clearance 0)
		)
		(min_thickness 0.25)
		(keepout
			(tracks allowed)
			(vias allowed)
			(pads allowed)
			(copperpour allowed)
			(footprints allowed)
		)
		(placement
			(enabled no)
			(sheetname "")
		)
		(fill
			(thermal_gap 0.5)
			(thermal_bridge_width 0.5)
			(island_removal_mode 0)
		)
		(polygon
			(pts
				(xy 26.20391 -285.516574) (xy 26.20391 -285.072836) (xy 28.529026 -285.072836) (xy 28.529026 -285.516574)
			)
		)
	)
	(zone
		(layer "F.Cu")
		(hatch none 0.5)
		(connect_pads
			(clearance 0)
		)
		(min_thickness 0.25)
		(keepout
			(tracks allowed)
			(vias allowed)
			(pads allowed)
			(copperpour allowed)
			(footprints allowed)
		)
		(placement
			(enabled no)
			(sheetname "")
		)
		(fill
			(thermal_gap 0.5)
			(thermal_bridge_width 0.5)
			(island_removal_mode 0)
		)
		(polygon
			(pts
				(xy 311.84088 -294.866568) (xy 311.84088 -294.42283) (xy 314.17768 -294.42283) (xy 314.17768 -294.866568)
			)
		)
	)
	(zone
		(layer "F.Cu")
		(hatch none 0.5)
		(connect_pads
			(clearance 0)
		)
		(min_thickness 0.25)
		(keepout
			(tracks allowed)
			(vias allowed)
			(pads allowed)
			(copperpour allowed)
			(footprints allowed)
		)
		(placement
			(enabled no)
			(sheetname "")
		)
		(fill
			(thermal_gap 0.5)
			(thermal_bridge_width 0.5)
			(island_removal_mode 0)
		)
		(polygon
			(pts
				(xy 307.76291 -198.816468) (xy 307.76291 -198.37273) (xy 310.088026 -198.37273) (xy 310.088026 -198.816468)
			)
		)
	)
	(zone
		(layer "F.Cu")
		(hatch none 0.5)
		(connect_pads
			(clearance 0)
		)
		(min_thickness 0.25)
		(keepout
			(tracks allowed)
			(vias allowed)
			(pads allowed)
			(copperpour allowed)
			(footprints not_allowed)
		)
		(placement
			(enabled no)
			(sheetname "")
		)
		(fill
			(thermal_gap 0.5)
			(thermal_bridge_width 0.5)
			(island_removal_mode 0)
		)
		(polygon
			(pts
				(xy 441.792106 -446.989962) (xy 441.792106 -438.989978) (xy 452.792084 -438.989978) (xy 452.792084 -446.989962)
			)
		)
	)
	(zone
		(layer "F.Cu")
		(hatch none 0.5)
		(connect_pads
			(clearance 0)
		)
		(min_thickness 0.25)
		(keepout
			(tracks allowed)
			(vias allowed)
			(pads allowed)
			(copperpour allowed)
			(footprints allowed)
		)
		(placement
			(enabled no)
			(sheetname "")
		)
		(fill
			(thermal_gap 0.5)
			(thermal_bridge_width 0.5)
			(island_removal_mode 0)
		)
		(polygon
			(pts
				(xy 165.335458 -293.05504) (xy 165.335458 -292.82644) (xy 167.367458 -292.82644) (xy 167.367458 -293.05504)
			)
		)
	)
	(zone
		(layer "F.Cu")
		(hatch none 0.5)
		(connect_pads
			(clearance 0)
		)
		(min_thickness 0.25)
		(keepout
			(tracks allowed)
			(vias allowed)
			(pads allowed)
			(copperpour allowed)
			(footprints allowed)
		)
		(placement
			(enabled no)
			(sheetname "")
		)
		(fill
			(thermal_gap 0.5)
			(thermal_bridge_width 0.5)
			(island_removal_mode 0)
		)
		(polygon
			(pts
				(xy 69.9643 -9.124188) (xy 69.9643 -6.327648) (xy 73.66 -6.327648) (xy 73.66 -9.124188)
			)
		)
	)
	(zone
		(layer "F.Cu")
		(hatch none 0.5)
		(connect_pads
			(clearance 0)
		)
		(min_thickness 0.25)
		(keepout
			(tracks allowed)
			(vias allowed)
			(pads allowed)
			(copperpour allowed)
			(footprints allowed)
		)
		(placement
			(enabled no)
			(sheetname "")
		)
		(fill
			(thermal_gap 0.5)
			(thermal_bridge_width 0.5)
			(island_removal_mode 0)
		)
		(polygon
			(pts
				(xy 210.598258 -248.854976) (xy 210.598258 -248.626376) (xy 212.630258 -248.626376) (xy 212.630258 -248.854976)
			)
		)
	)
	(zone
		(layer "F.Cu")
		(hatch none 0.5)
		(connect_pads
			(clearance 0)
		)
		(min_thickness 0.25)
		(keepout
			(tracks allowed)
			(vias allowed)
			(pads allowed)
			(copperpour allowed)
			(footprints allowed)
		)
		(placement
			(enabled no)
			(sheetname "")
		)
		(fill
			(thermal_gap 0.5)
			(thermal_bridge_width 0.5)
			(island_removal_mode 0)
		)
		(polygon
			(pts
				(xy 422.6433 -367.431828) (xy 422.6433 -364.688628) (xy 428.65294 -364.688628) (xy 428.65294 -367.431828)
			)
		)
	)
	(zone
		(layer "F.Cu")
		(hatch none 0.5)
		(connect_pads
			(clearance 0)
		)
		(min_thickness 0.25)
		(keepout
			(tracks allowed)
			(vias allowed)
			(pads allowed)
			(copperpour allowed)
			(footprints allowed)
		)
		(placement
			(enabled no)
			(sheetname "")
		)
		(fill
			(thermal_gap 0.5)
			(thermal_bridge_width 0.5)
			(island_removal_mode 0)
		)
		(polygon
			(pts
				(xy 29.647642 -293.166546) (xy 29.647642 -292.722808) (xy 31.972758 -292.722808) (xy 31.972758 -293.166546)
			)
		)
	)
	(zone
		(layer "F.Cu")
		(hatch none 0.5)
		(connect_pads
			(clearance 0)
		)
		(min_thickness 0.25)
		(keepout
			(tracks allowed)
			(vias allowed)
			(pads allowed)
			(copperpour allowed)
			(footprints allowed)
		)
		(placement
			(enabled no)
			(sheetname "")
		)
		(fill
			(thermal_gap 0.5)
			(thermal_bridge_width 0.5)
			(island_removal_mode 0)
		)
		(polygon
			(pts
				(xy 157.791658 -291.355018) (xy 157.791658 -291.126418) (xy 159.823658 -291.126418) (xy 159.823658 -291.355018)
			)
		)
	)
	(zone
		(layer "F.Cu")
		(hatch none 0.5)
		(connect_pads
			(clearance 0)
		)
		(min_thickness 0.25)
		(keepout
			(tracks allowed)
			(vias allowed)
			(pads allowed)
			(copperpour allowed)
			(footprints allowed)
		)
		(placement
			(enabled no)
			(sheetname "")
		)
		(fill
			(thermal_gap 0.5)
			(thermal_bridge_width 0.5)
			(island_removal_mode 0)
		)
		(polygon
			(pts
				(xy 192.066926 -297.076368) (xy 194.098926 -297.076368) (xy 194.098926 -297.304968) (xy 192.066926 -297.304968)
				(xy 191.930782 -297.304968) (xy 191.883792 -297.304968) (xy 191.883792 -297.076368) (xy 191.930782 -297.076368)
			)
		)
	)
	(zone
		(layer "F.Cu")
		(hatch none 0.5)
		(connect_pads
			(clearance 0)
		)
		(min_thickness 0.25)
		(keepout
			(tracks allowed)
			(vias allowed)
			(pads allowed)
			(copperpour allowed)
			(footprints allowed)
		)
		(placement
			(enabled no)
			(sheetname "")
		)
		(fill
			(thermal_gap 0.5)
			(thermal_bridge_width 0.5)
			(island_removal_mode 0)
		)
		(polygon
			(pts
				(xy 84.281772 -404.802594) (xy 84.281772 -399.959576) (xy 86.166198 -399.959576) (xy 86.166198 -404.802594)
			)
		)
	)
	(zone
		(layer "F.Cu")
		(hatch none 0.5)
		(connect_pads
			(clearance 0)
		)
		(min_thickness 0.25)
		(keepout
			(tracks allowed)
			(vias allowed)
			(pads allowed)
			(copperpour allowed)
			(footprints allowed)
		)
		(placement
			(enabled no)
			(sheetname "")
		)
		(fill
			(thermal_gap 0.5)
			(thermal_bridge_width 0.5)
			(island_removal_mode 0)
		)
		(polygon
			(pts
				(xy 262.50011 -239.616488) (xy 262.50011 -239.17275) (xy 264.825226 -239.17275) (xy 264.825226 -239.616488)
			)
		)
	)
	(zone
		(layer "F.Cu")
		(hatch none 0.5)
		(connect_pads
			(clearance 0)
		)
		(min_thickness 0.25)
		(keepout
			(tracks allowed)
			(vias allowed)
			(pads allowed)
			(copperpour allowed)
			(footprints not_allowed)
		)
		(placement
			(enabled no)
			(sheetname "")
		)
		(fill
			(thermal_gap 0.5)
			(thermal_bridge_width 0.5)
			(island_removal_mode 0)
		)
		(polygon
			(pts
				(xy 156.813504 -187.661804) (xy 156.813504 -185.091832) (xy 217.670126 -185.091832) (xy 217.670126 -168.661842)
				(xy 151.363426 -168.661842) (xy 151.363426 -187.661804)
			)
		)
	)
	(zone
		(layer "F.Cu")
		(hatch none 0.5)
		(connect_pads
			(clearance 0)
		)
		(min_thickness 0.25)
		(keepout
			(tracks allowed)
			(vias allowed)
			(pads allowed)
			(copperpour allowed)
			(footprints allowed)
		)
		(placement
			(enabled no)
			(sheetname "")
		)
		(fill
			(thermal_gap 0.5)
			(thermal_bridge_width 0.5)
			(island_removal_mode 0)
		)
		(polygon
			(pts
				(xy 383.655062 -330.491338) (xy 383.655062 -328.190098) (xy 388.026402 -328.190098) (xy 388.026402 -330.491338)
			)
		)
	)
	(zone
		(layer "F.Cu")
		(hatch none 0.5)
		(connect_pads
			(clearance 0)
		)
		(min_thickness 0.25)
		(keepout
			(tracks allowed)
			(vias allowed)
			(pads allowed)
			(copperpour allowed)
			(footprints allowed)
		)
		(placement
			(enabled no)
			(sheetname "")
		)
		(fill
			(thermal_gap 0.5)
			(thermal_bridge_width 0.5)
			(island_removal_mode 0)
		)
		(polygon
			(pts
				(xy 409.831794 -304.72634) (xy 411.863794 -304.72634) (xy 411.863794 -304.95494) (xy 409.831794 -304.95494)
				(xy 409.650692 -304.95494) (xy 409.650692 -304.72634)
			)
		)
	)
	(zone
		(layer "F.Cu")
		(hatch none 0.5)
		(connect_pads
			(clearance 0)
		)
		(min_thickness 0.25)
		(keepout
			(tracks allowed)
			(vias allowed)
			(pads allowed)
			(copperpour allowed)
			(footprints allowed)
		)
		(placement
			(enabled no)
			(sheetname "")
		)
		(fill
			(thermal_gap 0.5)
			(thermal_bridge_width 0.5)
			(island_removal_mode 0)
		)
		(polygon
			(pts
				(xy 304.319178 -214.96655) (xy 304.319178 -214.522812) (xy 306.644294 -214.522812) (xy 306.644294 -214.96655)
			)
		)
	)
	(zone
		(layer "F.Cu")
		(hatch none 0.5)
		(connect_pads
			(clearance 0)
		)
		(min_thickness 0.25)
		(keepout
			(tracks allowed)
			(vias allowed)
			(pads allowed)
			(copperpour allowed)
			(footprints allowed)
		)
		(placement
			(enabled no)
			(sheetname "")
		)
		(fill
			(thermal_gap 0.5)
			(thermal_bridge_width 0.5)
			(island_removal_mode 0)
		)
		(polygon
			(pts
				(xy 56.37911 -240.872772) (xy 58.704226 -240.872772) (xy 58.704226 -240.874042) (xy 58.786522 -240.874042)
				(xy 58.786522 -241.80419) (xy 56.24576 -241.80419) (xy 56.24576 -240.872772)
			)
		)
	)
	(zone
		(layer "F.Cu")
		(hatch none 0.5)
		(connect_pads
			(clearance 0)
		)
		(min_thickness 0.25)
		(keepout
			(tracks allowed)
			(vias allowed)
			(pads allowed)
			(copperpour allowed)
			(footprints allowed)
		)
		(placement
			(enabled no)
			(sheetname "")
		)
		(fill
			(thermal_gap 0.5)
			(thermal_bridge_width 0.5)
			(island_removal_mode 0)
		)
		(polygon
			(pts
				(xy 41.29151 -291.466524) (xy 41.29151 -291.022786) (xy 43.616626 -291.022786) (xy 43.616626 -291.466524)
			)
		)
	)
	(zone
		(layer "F.Cu")
		(hatch none 0.5)
		(connect_pads
			(clearance 0)
		)
		(min_thickness 0.25)
		(keepout
			(tracks allowed)
			(vias allowed)
			(pads allowed)
			(copperpour allowed)
			(footprints allowed)
		)
		(placement
			(enabled no)
			(sheetname "")
		)
		(fill
			(thermal_gap 0.5)
			(thermal_bridge_width 0.5)
			(island_removal_mode 0)
		)
		(polygon
			(pts
				(xy 180.423058 -214.85479) (xy 180.423058 -214.62619) (xy 182.455058 -214.62619) (xy 182.455058 -214.85479)
			)
		)
	)
	(zone
		(layer "F.Cu")
		(hatch none 0.5)
		(connect_pads
			(clearance 0)
		)
		(min_thickness 0.25)
		(keepout
			(tracks allowed)
			(vias allowed)
			(pads allowed)
			(copperpour allowed)
			(footprints allowed)
		)
		(placement
			(enabled no)
			(sheetname "")
		)
		(fill
			(thermal_gap 0.5)
			(thermal_bridge_width 0.5)
			(island_removal_mode 0)
		)
		(polygon
			(pts
				(xy 165.335458 -286.254952) (xy 165.335458 -286.026352) (xy 167.367458 -286.026352) (xy 167.367458 -286.254952)
			)
		)
	)
	(zone
		(layer "F.Cu")
		(hatch none 0.5)
		(connect_pads
			(clearance 0)
		)
		(min_thickness 0.25)
		(keepout
			(tracks allowed)
			(vias allowed)
			(pads allowed)
			(copperpour allowed)
			(footprints allowed)
		)
		(placement
			(enabled no)
			(sheetname "")
		)
		(fill
			(thermal_gap 0.5)
			(thermal_bridge_width 0.5)
			(island_removal_mode 0)
		)
		(polygon
			(pts
				(xy 385.77774 -216.878408) (xy 386.06476 -216.878408) (xy 386.09524 -216.847928) (xy 386.09524 -216.220548)
				(xy 386.00888 -216.134188) (xy 385.82092 -216.134188) (xy 385.74726 -216.207848) (xy 385.74726 -216.847928)
			)
		)
	)
	(zone
		(layer "F.Cu")
		(hatch none 0.5)
		(connect_pads
			(clearance 0)
		)
		(min_thickness 0.25)
		(keepout
			(tracks allowed)
			(vias allowed)
			(pads allowed)
			(copperpour allowed)
			(footprints allowed)
		)
		(placement
			(enabled no)
			(sheetname "")
		)
		(fill
			(thermal_gap 0.5)
			(thermal_bridge_width 0.5)
			(island_removal_mode 0)
		)
		(polygon
			(pts
				(xy 311.86628 -196.266562) (xy 311.86628 -195.822824) (xy 314.17768 -195.822824) (xy 314.17768 -196.266562)
			)
		)
	)
	(zone
		(layer "F.Cu")
		(hatch none 0.5)
		(connect_pads
			(clearance 0)
		)
		(min_thickness 0.25)
		(keepout
			(tracks allowed)
			(vias allowed)
			(pads allowed)
			(copperpour allowed)
			(footprints not_allowed)
		)
		(placement
			(enabled no)
			(sheetname "")
		)
		(fill
			(thermal_gap 0.5)
			(thermal_bridge_width 0.5)
			(island_removal_mode 0)
		)
		(polygon
			(pts
				(xy 271.068546 -6.780022) (xy 271.068546 -14.780006) (xy 260.068568 -14.780006) (xy 260.068568 -6.780022)
			)
		)
	)
	(zone
		(layer "F.Cu")
		(hatch none 0.5)
		(connect_pads
			(clearance 0)
		)
		(min_thickness 0.25)
		(keepout
			(tracks allowed)
			(vias allowed)
			(pads allowed)
			(copperpour allowed)
			(footprints allowed)
		)
		(placement
			(enabled no)
			(sheetname "")
		)
		(fill
			(thermal_gap 0.5)
			(thermal_bridge_width 0.5)
			(island_removal_mode 0)
		)
		(polygon
			(pts
				(xy 440.006994 -303.876202) (xy 442.038994 -303.876202) (xy 442.038994 -304.104802) (xy 440.006994 -304.104802)
				(xy 439.875676 -304.104802) (xy 439.849768 -304.104802) (xy 439.849768 -303.876202) (xy 439.875676 -303.876202)
			)
		)
	)
	(zone
		(layer "F.Cu")
		(hatch none 0.5)
		(connect_pads
			(clearance 0)
		)
		(min_thickness 0.25)
		(keepout
			(tracks allowed)
			(vias allowed)
			(pads allowed)
			(copperpour allowed)
			(footprints allowed)
		)
		(placement
			(enabled no)
			(sheetname "")
		)
		(fill
			(thermal_gap 0.5)
			(thermal_bridge_width 0.5)
			(island_removal_mode 0)
		)
		(polygon
			(pts
				(xy 458.538326 -278.60498) (xy 458.538326 -278.37638) (xy 460.570326 -278.37638) (xy 460.570326 -278.60498)
			)
		)
	)
	(zone
		(layer "F.Cu")
		(hatch none 0.5)
		(connect_pads
			(clearance 0)
		)
		(min_thickness 0.25)
		(keepout
			(tracks not_allowed)
			(vias allowed)
			(pads allowed)
			(copperpour not_allowed)
			(footprints allowed)
		)
		(placement
			(enabled no)
			(sheetname "")
		)
		(fill
			(thermal_gap 0.5)
			(thermal_bridge_width 0.5)
			(island_removal_mode 0)
		)
		(polygon
			(pts
				(arc
					(start 383.454656 -297.515026)
					(mid 381.359664 -299.610018)
					(end 379.264672 -297.515026)
				)
				(arc
					(start 379.264672 -297.515026)
					(mid 381.359664 -295.420034)
					(end 383.454656 -297.515026)
				)
			)
		)
	)
	(zone
		(layer "F.Cu")
		(hatch none 0.5)
		(connect_pads
			(clearance 0)
		)
		(min_thickness 0.25)
		(keepout
			(tracks allowed)
			(vias allowed)
			(pads allowed)
			(copperpour allowed)
			(footprints allowed)
		)
		(placement
			(enabled no)
			(sheetname "")
		)
		(fill
			(thermal_gap 0.5)
			(thermal_bridge_width 0.5)
			(island_removal_mode 0)
		)
		(polygon
			(pts
				(xy 333.11338 -342.857328) (xy 333.11338 -339.801708) (xy 338.66328 -339.801708) (xy 338.66328 -342.857328)
			)
		)
	)
	(zone
		(layer "F.Cu")
		(hatch none 0.5)
		(connect_pads
			(clearance 0)
		)
		(min_thickness 0.25)
		(keepout
			(tracks allowed)
			(vias allowed)
			(pads allowed)
			(copperpour allowed)
			(footprints allowed)
		)
		(placement
			(enabled no)
			(sheetname "")
		)
		(fill
			(thermal_gap 0.5)
			(thermal_bridge_width 0.5)
			(island_removal_mode 0)
		)
		(polygon
			(pts
				(xy 29.647642 -302.51654) (xy 29.647642 -302.072802) (xy 31.972758 -302.072802) (xy 31.972758 -302.51654)
			)
		)
	)
	(zone
		(layer "F.Cu")
		(hatch none 0.5)
		(connect_pads
			(clearance 0)
		)
		(min_thickness 0.25)
		(keepout
			(tracks allowed)
			(vias allowed)
			(pads allowed)
			(copperpour allowed)
			(footprints allowed)
		)
		(placement
			(enabled no)
			(sheetname "")
		)
		(fill
			(thermal_gap 0.5)
			(thermal_bridge_width 0.5)
			(island_removal_mode 0)
		)
		(polygon
			(pts
				(xy 26.20391 -207.316578) (xy 26.20391 -206.87284) (xy 28.529026 -206.87284) (xy 28.529026 -207.316578)
			)
		)
	)
	(zone
		(layer "F.Cu")
		(hatch none 0.5)
		(connect_pads
			(clearance 0)
		)
		(min_thickness 0.25)
		(keepout
			(tracks allowed)
			(vias allowed)
			(pads allowed)
			(copperpour allowed)
			(footprints allowed)
		)
		(placement
			(enabled no)
			(sheetname "")
		)
		(fill
			(thermal_gap 0.5)
			(thermal_bridge_width 0.5)
			(island_removal_mode 0)
		)
		(polygon
			(pts
				(xy 211.75218 -23.990808) (xy 211.75218 -19.906488) (xy 215.76284 -19.906488) (xy 215.76284 -23.990808)
			)
		)
	)
	(zone
		(layer "F.Cu")
		(hatch none 0.5)
		(connect_pads
			(clearance 0)
		)
		(min_thickness 0.25)
		(keepout
			(tracks allowed)
			(vias allowed)
			(pads allowed)
			(copperpour allowed)
			(footprints allowed)
		)
		(placement
			(enabled no)
			(sheetname "")
		)
		(fill
			(thermal_gap 0.5)
			(thermal_bridge_width 0.5)
			(island_removal_mode 0)
		)
		(polygon
			(pts
				(xy 415.318702 -274.35683) (xy 413.286702 -274.35683) (xy 413.286702 -274.354544) (xy 413.107886 -274.354544)
				(xy 412.91764 -274.354544) (xy 412.91764 -274.074128) (xy 412.7881 -274.074128) (xy 412.7881 -273.564604)
				(xy 412.999428 -273.564604) (xy 415.539682 -273.564604) (xy 415.846768 -273.564604) (xy 415.846768 -274.065746)
				(xy 415.72688 -274.065746) (xy 415.72688 -274.35683) (xy 415.670238 -274.35683) (xy 415.62528 -274.35683)
				(xy 415.599372 -274.35683) (xy 415.501836 -274.35683) (xy 415.454846 -274.35683)
			)
		)
	)
	(zone
		(layer "F.Cu")
		(hatch none 0.5)
		(connect_pads
			(clearance 0)
		)
		(min_thickness 0.25)
		(keepout
			(tracks allowed)
			(vias allowed)
			(pads allowed)
			(copperpour allowed)
			(footprints allowed)
		)
		(placement
			(enabled no)
			(sheetname "")
		)
		(fill
			(thermal_gap 0.5)
			(thermal_bridge_width 0.5)
			(island_removal_mode 0)
		)
		(polygon
			(pts
				(xy 358.725724 -331.689456) (xy 358.725724 -335.695036) (xy 359.205784 -336.175096) (xy 361.270804 -336.175096)
				(xy 361.542584 -335.903316) (xy 361.542584 -334.049116) (xy 361.794044 -333.797656) (xy 363.714284 -333.797656)
				(xy 364.130844 -333.381096) (xy 364.130844 -331.890116) (xy 363.483144 -331.242416) (xy 359.172764 -331.242416)
			)
		)
	)
	(zone
		(layer "F.Cu")
		(hatch none 0.5)
		(connect_pads
			(clearance 0)
		)
		(min_thickness 0.25)
		(keepout
			(tracks allowed)
			(vias allowed)
			(pads allowed)
			(copperpour allowed)
			(footprints allowed)
		)
		(placement
			(enabled no)
			(sheetname "")
		)
		(fill
			(thermal_gap 0.5)
			(thermal_bridge_width 0.5)
			(island_removal_mode 0)
		)
		(polygon
			(pts
				(xy 63.951612 -240.872772) (xy 66.212212 -240.872772) (xy 66.30416 -240.872772) (xy 66.30416 -241.79276)
				(xy 63.795656 -241.79276) (xy 63.795656 -240.872772)
			)
		)
	)
	(zone
		(layer "F.Cu")
		(hatch none 0.5)
		(connect_pads
			(clearance 0)
		)
		(min_thickness 0.25)
		(keepout
			(tracks allowed)
			(vias allowed)
			(pads allowed)
			(copperpour allowed)
			(footprints allowed)
		)
		(placement
			(enabled no)
			(sheetname "")
		)
		(fill
			(thermal_gap 0.5)
			(thermal_bridge_width 0.5)
			(island_removal_mode 0)
		)
		(polygon
			(pts
				(xy 161.891726 -272.42643) (xy 163.923726 -272.42643) (xy 163.923726 -272.428716) (xy 164.102542 -272.428716)
				(xy 164.283644 -272.428716) (xy 164.311076 -272.428716) (xy 164.311076 -273.218656) (xy 164.211 -273.218656)
				(xy 161.670746 -273.218656) (xy 161.48685 -273.218656) (xy 161.48685 -272.42643) (xy 161.529522 -272.42643)
				(xy 161.611056 -272.42643) (xy 161.708592 -272.42643) (xy 161.755582 -272.42643)
			)
		)
	)
	(zone
		(layer "F.Cu")
		(hatch none 0.5)
		(connect_pads
			(clearance 0)
		)
		(min_thickness 0.25)
		(keepout
			(tracks allowed)
			(vias allowed)
			(pads allowed)
			(copperpour allowed)
			(footprints allowed)
		)
		(placement
			(enabled no)
			(sheetname "")
		)
		(fill
			(thermal_gap 0.5)
			(thermal_bridge_width 0.5)
			(island_removal_mode 0)
		)
		(polygon
			(pts
				(xy 311.94248 -315.266578) (xy 311.94248 -314.82284) (xy 314.10148 -314.82284) (xy 314.10148 -315.266578)
			)
		)
	)
	(zone
		(layer "F.Cu")
		(hatch none 0.5)
		(connect_pads
			(clearance 0)
		)
		(min_thickness 0.25)
		(keepout
			(tracks allowed)
			(vias allowed)
			(pads allowed)
			(copperpour allowed)
			(footprints allowed)
		)
		(placement
			(enabled no)
			(sheetname "")
		)
		(fill
			(thermal_gap 0.5)
			(thermal_bridge_width 0.5)
			(island_removal_mode 0)
		)
		(polygon
			(pts
				(xy 356.35438 -339.021928) (xy 356.35438 -334.317848) (xy 363.09046 -334.317848) (xy 363.09046 -339.021928)
			)
		)
	)
	(zone
		(layer "F.Cu")
		(hatch none 0.5)
		(connect_pads
			(clearance 0)
		)
		(min_thickness 0.25)
		(keepout
			(tracks not_allowed)
			(vias allowed)
			(pads allowed)
			(copperpour not_allowed)
			(footprints allowed)
		)
		(placement
			(enabled no)
			(sheetname "")
		)
		(fill
			(thermal_gap 0.5)
			(thermal_bridge_width 0.5)
			(island_removal_mode 0)
		)
		(polygon
			(pts
				(arc
					(start 466.39988 -32.29991)
					(mid 464.799934 -30.699964)
					(end 463.199988 -32.29991)
				)
				(arc
					(start 463.199988 -33.899856)
					(mid 464.799934 -35.499802)
					(end 466.39988 -33.899856)
				)
			)
		)
	)
	(zone
		(layer "F.Cu")
		(hatch none 0.5)
		(connect_pads
			(clearance 0)
		)
		(min_thickness 0.25)
		(keepout
			(tracks allowed)
			(vias allowed)
			(pads allowed)
			(copperpour allowed)
			(footprints allowed)
		)
		(placement
			(enabled no)
			(sheetname "")
		)
		(fill
			(thermal_gap 0.5)
			(thermal_bridge_width 0.5)
			(island_removal_mode 0)
		)
		(polygon
			(pts
				(xy 29.647642 -295.716452) (xy 29.647642 -295.272714) (xy 31.972758 -295.272714) (xy 31.972758 -295.716452)
			)
		)
	)
	(zone
		(layer "F.Cu")
		(hatch none 0.5)
		(connect_pads
			(clearance 0)
		)
		(min_thickness 0.25)
		(keepout
			(tracks allowed)
			(vias allowed)
			(pads allowed)
			(copperpour allowed)
			(footprints allowed)
		)
		(placement
			(enabled no)
			(sheetname "")
		)
		(fill
			(thermal_gap 0.5)
			(thermal_bridge_width 0.5)
			(island_removal_mode 0)
		)
		(polygon
			(pts
				(xy 289.231578 -260.866636) (xy 289.231578 -260.422898) (xy 291.556694 -260.422898) (xy 291.556694 -260.866636)
			)
		)
	)
	(zone
		(layer "F.Cu")
		(hatch none 0.5)
		(connect_pads
			(clearance 0)
		)
		(min_thickness 0.25)
		(keepout
			(tracks allowed)
			(vias allowed)
			(pads allowed)
			(copperpour allowed)
			(footprints allowed)
		)
		(placement
			(enabled no)
			(sheetname "")
		)
		(fill
			(thermal_gap 0.5)
			(thermal_bridge_width 0.5)
			(island_removal_mode 0)
		)
		(polygon
			(pts
				(xy 165.335458 -227.604828) (xy 165.335458 -227.376228) (xy 167.367458 -227.376228) (xy 167.367458 -227.604828)
			)
		)
	)
	(zone
		(layer "F.Cu")
		(hatch none 0.5)
		(connect_pads
			(clearance 0)
		)
		(min_thickness 0.25)
		(keepout
			(tracks allowed)
			(vias allowed)
			(pads allowed)
			(copperpour allowed)
			(footprints allowed)
		)
		(placement
			(enabled no)
			(sheetname "")
		)
		(fill
			(thermal_gap 0.5)
			(thermal_bridge_width 0.5)
			(island_removal_mode 0)
		)
		(polygon
			(pts
				(xy 340.282022 -404.802594) (xy 340.282022 -399.959576) (xy 342.166448 -399.959576) (xy 342.166448 -404.802594)
			)
		)
	)
	(zone
		(layer "F.Cu")
		(hatch none 0.5)
		(connect_pads
			(clearance 0)
		)
		(min_thickness 0.25)
		(keepout
			(tracks allowed)
			(vias allowed)
			(pads allowed)
			(copperpour allowed)
			(footprints allowed)
		)
		(placement
			(enabled no)
			(sheetname "")
		)
		(fill
			(thermal_gap 0.5)
			(thermal_bridge_width 0.5)
			(island_removal_mode 0)
		)
		(polygon
			(pts
				(xy 87.06612 -218.455748) (xy 87.35314 -218.455748) (xy 87.38362 -218.425268) (xy 87.38362 -217.797888)
				(xy 87.29726 -217.711528) (xy 87.1093 -217.711528) (xy 87.03564 -217.785188) (xy 87.03564 -218.425268)
			)
		)
	)
	(zone
		(layer "F.Cu")
		(hatch none 0.5)
		(connect_pads
			(clearance 0)
		)
		(min_thickness 0.25)
		(keepout
			(tracks allowed)
			(vias allowed)
			(pads allowed)
			(copperpour allowed)
			(footprints allowed)
		)
		(placement
			(enabled no)
			(sheetname "")
		)
		(fill
			(thermal_gap 0.5)
			(thermal_bridge_width 0.5)
			(island_removal_mode 0)
		)
		(polygon
			(pts
				(xy 458.538326 -208.054956) (xy 458.538326 -207.826356) (xy 460.570326 -207.826356) (xy 460.570326 -208.054956)
			)
		)
	)
	(zone
		(layer "F.Cu")
		(hatch none 0.5)
		(connect_pads
			(clearance 0)
		)
		(min_thickness 0.25)
		(keepout
			(tracks allowed)
			(vias allowed)
			(pads allowed)
			(copperpour allowed)
			(footprints allowed)
		)
		(placement
			(enabled no)
			(sheetname "")
		)
		(fill
			(thermal_gap 0.5)
			(thermal_bridge_width 0.5)
			(island_removal_mode 0)
		)
		(polygon
			(pts
				(xy 405.731726 -287.954974) (xy 405.731726 -287.726374) (xy 407.763726 -287.726374) (xy 407.763726 -287.954974)
			)
		)
	)
	(zone
		(layer "F.Cu")
		(hatch none 0.5)
		(connect_pads
			(clearance 0)
		)
		(min_thickness 0.25)
		(keepout
			(tracks allowed)
			(vias allowed)
			(pads allowed)
			(copperpour allowed)
			(footprints allowed)
		)
		(placement
			(enabled no)
			(sheetname "")
		)
		(fill
			(thermal_gap 0.5)
			(thermal_bridge_width 0.5)
			(island_removal_mode 0)
		)
		(polygon
			(pts
				(xy 455.094594 -203.576428) (xy 457.126594 -203.576428) (xy 457.126594 -203.805028) (xy 455.094594 -203.805028)
				(xy 454.95845 -203.805028) (xy 454.91146 -203.805028) (xy 454.91146 -203.576428) (xy 454.95845 -203.576428)
			)
		)
	)
	(zone
		(layer "F.Cu")
		(hatch none 0.5)
		(connect_pads
			(clearance 0)
		)
		(min_thickness 0.25)
		(keepout
			(tracks allowed)
			(vias allowed)
			(pads allowed)
			(copperpour allowed)
			(footprints allowed)
		)
		(placement
			(enabled no)
			(sheetname "")
		)
		(fill
			(thermal_gap 0.5)
			(thermal_bridge_width 0.5)
			(island_removal_mode 0)
		)
		(polygon
			(pts
				(xy 207.154526 -206.976472) (xy 209.186526 -206.976472) (xy 209.186526 -207.205072) (xy 207.154526 -207.205072)
				(xy 207.018382 -207.205072) (xy 206.971392 -207.205072) (xy 206.971392 -206.976472) (xy 207.018382 -206.976472)
			)
		)
	)
	(zone
		(layer "F.Cu")
		(hatch none 0.5)
		(connect_pads
			(clearance 0)
		)
		(min_thickness 0.25)
		(keepout
			(tracks allowed)
			(vias allowed)
			(pads allowed)
			(copperpour allowed)
			(footprints allowed)
		)
		(placement
			(enabled no)
			(sheetname "")
		)
		(fill
			(thermal_gap 0.5)
			(thermal_bridge_width 0.5)
			(island_removal_mode 0)
		)
		(polygon
			(pts
				(xy 79.792068 -342.109298) (xy 77.975968 -342.109298) (xy 77.975968 -340.730078) (xy 79.792068 -340.730078)
			)
		)
	)
	(zone
		(layer "F.Cu")
		(hatch none 0.5)
		(connect_pads
			(clearance 0)
		)
		(min_thickness 0.25)
		(keepout
			(tracks allowed)
			(vias allowed)
			(pads allowed)
			(copperpour allowed)
			(footprints allowed)
		)
		(placement
			(enabled no)
			(sheetname "")
		)
		(fill
			(thermal_gap 0.5)
			(thermal_bridge_width 0.5)
			(island_removal_mode 0)
		)
		(polygon
			(pts
				(xy 334.547972 -324.708012) (xy 334.547972 -322.406772) (xy 338.919312 -322.406772) (xy 338.919312 -324.708012)
			)
		)
	)
	(zone
		(layer "F.Cu")
		(hatch none 0.5)
		(connect_pads
			(clearance 0)
		)
		(min_thickness 0.25)
		(keepout
			(tracks allowed)
			(vias allowed)
			(pads allowed)
			(copperpour allowed)
			(footprints allowed)
		)
		(placement
			(enabled no)
			(sheetname "")
		)
		(fill
			(thermal_gap 0.5)
			(thermal_bridge_width 0.5)
			(island_removal_mode 0)
		)
		(polygon
			(pts
				(xy 210.598258 -199.554846) (xy 210.598258 -199.326246) (xy 212.630258 -199.326246) (xy 212.630258 -199.554846)
			)
		)
	)
	(zone
		(layer "F.Cu")
		(hatch none 0.5)
		(connect_pads
			(clearance 0)
		)
		(min_thickness 0.25)
		(keepout
			(tracks allowed)
			(vias allowed)
			(pads allowed)
			(copperpour allowed)
			(footprints allowed)
		)
		(placement
			(enabled no)
			(sheetname "")
		)
		(fill
			(thermal_gap 0.5)
			(thermal_bridge_width 0.5)
			(island_removal_mode 0)
		)
		(polygon
			(pts
				(xy 307.76291 -289.766502) (xy 307.76291 -289.322764) (xy 310.088026 -289.322764) (xy 310.088026 -289.766502)
			)
		)
	)
	(zone
		(layer "F.Cu")
		(hatch none 0.5)
		(connect_pads
			(clearance 0)
		)
		(min_thickness 0.25)
		(keepout
			(tracks allowed)
			(vias allowed)
			(pads allowed)
			(copperpour allowed)
			(footprints allowed)
		)
		(placement
			(enabled no)
			(sheetname "")
		)
		(fill
			(thermal_gap 0.5)
			(thermal_bridge_width 0.5)
			(island_removal_mode 0)
		)
		(polygon
			(pts
				(xy 63.977012 -309.316628) (xy 63.977012 -308.87289) (xy 66.212212 -308.87289) (xy 66.212212 -309.316628)
			)
		)
	)
	(zone
		(layer "F.Cu")
		(hatch none 0.5)
		(connect_pads
			(clearance 0)
		)
		(min_thickness 0.25)
		(keepout
			(tracks allowed)
			(vias allowed)
			(pads allowed)
			(copperpour allowed)
			(footprints allowed)
		)
		(placement
			(enabled no)
			(sheetname "")
		)
		(fill
			(thermal_gap 0.5)
			(thermal_bridge_width 0.5)
			(island_removal_mode 0)
		)
		(polygon
			(pts
				(xy 413.275526 -231.85501) (xy 413.275526 -231.62641) (xy 415.307526 -231.62641) (xy 415.307526 -231.85501)
			)
		)
	)
	(zone
		(layer "F.Cu")
		(hatch none 0.5)
		(connect_pads
			(clearance 0)
		)
		(min_thickness 0.25)
		(keepout
			(tracks allowed)
			(vias allowed)
			(pads allowed)
			(copperpour allowed)
			(footprints allowed)
		)
		(placement
			(enabled no)
			(sheetname "")
		)
		(fill
			(thermal_gap 0.5)
			(thermal_bridge_width 0.5)
			(island_removal_mode 0)
		)
		(polygon
			(pts
				(xy 180.423058 -265.854942) (xy 180.423058 -265.626342) (xy 182.455058 -265.626342) (xy 182.455058 -265.854942)
			)
		)
	)
	(zone
		(layer "F.Cu")
		(hatch none 0.5)
		(connect_pads
			(clearance 0)
		)
		(min_thickness 0.25)
		(keepout
			(tracks allowed)
			(vias allowed)
			(pads allowed)
			(copperpour allowed)
			(footprints allowed)
		)
		(placement
			(enabled no)
			(sheetname "")
		)
		(fill
			(thermal_gap 0.5)
			(thermal_bridge_width 0.5)
			(island_removal_mode 0)
		)
		(polygon
			(pts
				(xy 424.919394 -225.67646) (xy 426.951394 -225.67646) (xy 426.951394 -225.90506) (xy 424.919394 -225.90506)
				(xy 424.78325 -225.90506) (xy 424.73626 -225.90506) (xy 424.73626 -225.67646) (xy 424.78325 -225.67646)
			)
		)
	)
	(zone
		(layer "F.Cu")
		(hatch none 0.5)
		(connect_pads
			(clearance 0)
		)
		(min_thickness 0.25)
		(keepout
			(tracks allowed)
			(vias allowed)
			(pads allowed)
			(copperpour allowed)
			(footprints allowed)
		)
		(placement
			(enabled no)
			(sheetname "")
		)
		(fill
			(thermal_gap 0.5)
			(thermal_bridge_width 0.5)
			(island_removal_mode 0)
		)
		(polygon
			(pts
				(xy 277.58771 -221.766638) (xy 277.58771 -221.3229) (xy 279.912826 -221.3229) (xy 279.912826 -221.766638)
			)
		)
	)
	(zone
		(layer "F.Cu")
		(hatch none 0.5)
		(connect_pads
			(clearance 0)
		)
		(min_thickness 0.25)
		(keepout
			(tracks allowed)
			(vias allowed)
			(pads allowed)
			(copperpour allowed)
			(footprints allowed)
		)
		(placement
			(enabled no)
			(sheetname "")
		)
		(fill
			(thermal_gap 0.5)
			(thermal_bridge_width 0.5)
			(island_removal_mode 0)
		)
		(polygon
			(pts
				(xy 63.977012 -296.56659) (xy 63.977012 -296.122852) (xy 66.186812 -296.122852) (xy 66.186812 -296.56659)
			)
		)
	)
	(zone
		(layer "F.Cu")
		(hatch none 0.5)
		(connect_pads
			(clearance 0)
		)
		(min_thickness 0.25)
		(keepout
			(tracks not_allowed)
			(vias allowed)
			(pads allowed)
			(copperpour not_allowed)
			(footprints allowed)
		)
		(placement
			(enabled no)
			(sheetname "")
		)
		(fill
			(thermal_gap 0.5)
			(thermal_bridge_width 0.5)
			(island_removal_mode 0)
		)
		(polygon
			(pts
				(xy 63.66891 -11.992356) (xy 63.84417 -11.992356) (xy 63.87211 -11.964416) (xy 63.87211 -10.569956)
				(xy 63.84925 -10.547096) (xy 63.67907 -10.547096) (xy 63.65875 -10.567416) (xy 63.65875 -11.982196)
			)
		)
	)
	(zone
		(layer "F.Cu")
		(hatch none 0.5)
		(connect_pads
			(clearance 0)
		)
		(min_thickness 0.25)
		(keepout
			(tracks allowed)
			(vias allowed)
			(pads allowed)
			(copperpour allowed)
			(footprints allowed)
		)
		(placement
			(enabled no)
			(sheetname "")
		)
		(fill
			(thermal_gap 0.5)
			(thermal_bridge_width 0.5)
			(island_removal_mode 0)
		)
		(polygon
			(pts
				(xy 207.154526 -249.47626) (xy 209.186526 -249.47626) (xy 209.186526 -249.70486) (xy 207.154526 -249.70486)
				(xy 206.987902 -249.70486) (xy 206.987902 -249.47626)
			)
		)
	)
	(zone
		(layer "F.Cu")
		(hatch none 0.5)
		(connect_pads
			(clearance 0)
		)
		(min_thickness 0.25)
		(keepout
			(tracks allowed)
			(vias allowed)
			(pads allowed)
			(copperpour allowed)
			(footprints allowed)
		)
		(placement
			(enabled no)
			(sheetname "")
		)
		(fill
			(thermal_gap 0.5)
			(thermal_bridge_width 0.5)
			(island_removal_mode 0)
		)
		(polygon
			(pts
				(xy 63.951612 -284.666436) (xy 63.951612 -284.222698) (xy 66.237612 -284.222698) (xy 66.237612 -284.666436)
			)
		)
	)
	(zone
		(layer "F.Cu")
		(hatch none 0.5)
		(connect_pads
			(clearance 0)
		)
		(min_thickness 0.25)
		(keepout
			(tracks allowed)
			(vias allowed)
			(pads allowed)
			(copperpour allowed)
			(footprints allowed)
		)
		(placement
			(enabled no)
			(sheetname "")
		)
		(fill
			(thermal_gap 0.5)
			(thermal_bridge_width 0.5)
			(island_removal_mode 0)
		)
		(polygon
			(pts
				(xy 415.201862 -163.07054) (xy 415.201862 -164.88664) (xy 413.822642 -164.88664) (xy 413.822642 -163.07054)
			)
		)
	)
	(zone
		(layer "F.Cu")
		(hatch none 0.5)
		(connect_pads
			(clearance 0)
		)
		(min_thickness 0.25)
		(keepout
			(tracks allowed)
			(vias allowed)
			(pads allowed)
			(copperpour allowed)
			(footprints allowed)
		)
		(placement
			(enabled no)
			(sheetname "")
		)
		(fill
			(thermal_gap 0.5)
			(thermal_bridge_width 0.5)
			(island_removal_mode 0)
		)
		(polygon
			(pts
				(xy 443.450726 -220.804994) (xy 443.450726 -220.576394) (xy 445.482726 -220.576394) (xy 445.482726 -220.804994)
			)
		)
	)
	(zone
		(layer "F.Cu")
		(hatch none 0.5)
		(connect_pads
			(clearance 0)
		)
		(min_thickness 0.25)
		(keepout
			(tracks allowed)
			(vias allowed)
			(pads allowed)
			(copperpour allowed)
			(footprints allowed)
		)
		(placement
			(enabled no)
			(sheetname "")
		)
		(fill
			(thermal_gap 0.5)
			(thermal_bridge_width 0.5)
			(island_removal_mode 0)
		)
		(polygon
			(pts
				(xy 455.094594 -210.376262) (xy 457.126594 -210.376262) (xy 457.126594 -210.604862) (xy 455.094594 -210.604862)
				(xy 454.963276 -210.604862) (xy 454.937368 -210.604862) (xy 454.937368 -210.376262) (xy 454.963276 -210.376262)
			)
		)
	)
	(zone
		(layer "F.Cu")
		(hatch none 0.5)
		(connect_pads
			(clearance 0)
		)
		(min_thickness 0.25)
		(keepout
			(tracks allowed)
			(vias allowed)
			(pads allowed)
			(copperpour allowed)
			(footprints allowed)
		)
		(placement
			(enabled no)
			(sheetname "")
		)
		(fill
			(thermal_gap 0.5)
			(thermal_bridge_width 0.5)
			(island_removal_mode 0)
		)
		(polygon
			(pts
				(xy 192.066926 -214.626444) (xy 194.098926 -214.626444) (xy 194.098926 -214.855044) (xy 192.066926 -214.855044)
				(xy 191.930782 -214.855044) (xy 191.883792 -214.855044) (xy 191.883792 -214.626444) (xy 191.930782 -214.626444)
			)
		)
	)
	(zone
		(layer "F.Cu")
		(hatch none 0.5)
		(connect_pads
			(clearance 0)
		)
		(min_thickness 0.25)
		(keepout
			(tracks allowed)
			(vias allowed)
			(pads allowed)
			(copperpour allowed)
			(footprints not_allowed)
		)
		(placement
			(enabled no)
			(sheetname "")
		)
		(fill
			(thermal_gap 0.5)
			(thermal_bridge_width 0.5)
			(island_removal_mode 0)
		)
		(polygon
			(pts
				(xy 476.79991 -4.619244) (xy 468.799926 -4.619244) (xy 468.799926 6.380734) (xy 476.79991 6.380734)
			)
		)
	)
	(zone
		(layer "F.Cu")
		(hatch none 0.5)
		(connect_pads
			(clearance 0)
		)
		(min_thickness 0.25)
		(keepout
			(tracks allowed)
			(vias allowed)
			(pads allowed)
			(copperpour allowed)
			(footprints allowed)
		)
		(placement
			(enabled no)
			(sheetname "")
		)
		(fill
			(thermal_gap 0.5)
			(thermal_bridge_width 0.5)
			(island_removal_mode 0)
		)
		(polygon
			(pts
				(xy 157.848554 -242.676426) (xy 159.778954 -242.676426) (xy 159.778954 -242.905026) (xy 157.848554 -242.905026)
				(xy 157.584902 -242.905026) (xy 157.584902 -242.676426)
			)
		)
	)
	(zone
		(layer "F.Cu")
		(hatch none 0.5)
		(connect_pads
			(clearance 0)
		)
		(min_thickness 0.25)
		(keepout
			(tracks allowed)
			(vias allowed)
			(pads allowed)
			(copperpour allowed)
			(footprints allowed)
		)
		(placement
			(enabled no)
			(sheetname "")
		)
		(fill
			(thermal_gap 0.5)
			(thermal_bridge_width 0.5)
			(island_removal_mode 0)
		)
		(polygon
			(pts
				(xy 151.676608 -410.948886) (xy 151.676608 -406.105868) (xy 153.561034 -406.105868) (xy 153.561034 -410.948886)
			)
		)
	)
	(zone
		(layer "F.Cu")
		(hatch none 0.5)
		(connect_pads
			(clearance 0)
		)
		(min_thickness 0.25)
		(keepout
			(tracks allowed)
			(vias allowed)
			(pads allowed)
			(copperpour allowed)
			(footprints allowed)
		)
		(placement
			(enabled no)
			(sheetname "")
		)
		(fill
			(thermal_gap 0.5)
			(thermal_bridge_width 0.5)
			(island_removal_mode 0)
		)
		(polygon
			(pts
				(xy 405.731726 -238.654844) (xy 405.731726 -238.426244) (xy 407.763726 -238.426244) (xy 407.763726 -238.654844)
			)
		)
	)
	(zone
		(layer "F.Cu")
		(hatch none 0.5)
		(connect_pads
			(clearance 0)
		)
		(min_thickness 0.25)
		(keepout
			(tracks allowed)
			(vias allowed)
			(pads allowed)
			(copperpour allowed)
			(footprints allowed)
		)
		(placement
			(enabled no)
			(sheetname "")
		)
		(fill
			(thermal_gap 0.5)
			(thermal_bridge_width 0.5)
			(island_removal_mode 0)
		)
		(polygon
			(pts
				(xy 44.735242 -269.366492) (xy 44.735242 -268.922754) (xy 47.060358 -268.922754) (xy 47.060358 -269.366492)
			)
		)
	)
	(zone
		(layer "F.Cu")
		(hatch none 0.5)
		(connect_pads
			(clearance 0)
		)
		(min_thickness 0.25)
		(keepout
			(tracks not_allowed)
			(vias allowed)
			(pads allowed)
			(copperpour not_allowed)
			(footprints allowed)
		)
		(placement
			(enabled no)
			(sheetname "")
		)
		(fill
			(thermal_gap 0.5)
			(thermal_bridge_width 0.5)
			(island_removal_mode 0)
		)
		(polygon
			(pts
				(xy 54.699154 -150.342092) (xy 54.948836 -150.342092) (xy 54.948836 -148.031708) (xy 54.64302 -148.031708)
				(xy 54.64302 -147.89404) (xy 52.59578 -147.89404) (xy 52.59578 -146.03984) (xy 52.836826 -146.03984)
				(xy 52.836826 -145.797524) (xy 52.355242 -145.797524) (xy 52.355242 -149.746208) (xy 52.540154 -149.561296)
				(xy 52.540154 -148.185378) (xy 54.699154 -148.185378)
			)
		)
	)
	(zone
		(layer "F.Cu")
		(hatch none 0.5)
		(connect_pads
			(clearance 0)
		)
		(min_thickness 0.25)
		(keepout
			(tracks allowed)
			(vias allowed)
			(pads allowed)
			(copperpour allowed)
			(footprints allowed)
		)
		(placement
			(enabled no)
			(sheetname "")
		)
		(fill
			(thermal_gap 0.5)
			(thermal_bridge_width 0.5)
			(island_removal_mode 0)
		)
		(polygon
			(pts
				(xy 14.560042 -237.066582) (xy 14.560042 -236.622844) (xy 16.885158 -236.622844) (xy 16.885158 -237.066582)
			)
		)
	)
	(zone
		(layer "F.Cu")
		(hatch none 0.5)
		(connect_pads
			(clearance 0)
		)
		(min_thickness 0.25)
		(keepout
			(tracks allowed)
			(vias allowed)
			(pads allowed)
			(copperpour allowed)
			(footprints allowed)
		)
		(placement
			(enabled no)
			(sheetname "")
		)
		(fill
			(thermal_gap 0.5)
			(thermal_bridge_width 0.5)
			(island_removal_mode 0)
		)
		(polygon
			(pts
				(xy 458.538326 -203.805028) (xy 458.538326 -203.576428) (xy 460.570326 -203.576428) (xy 460.570326 -203.805028)
			)
		)
	)
	(zone
		(layer "F.Cu")
		(hatch none 0.5)
		(connect_pads
			(clearance 0)
		)
		(min_thickness 0.25)
		(keepout
			(tracks allowed)
			(vias allowed)
			(pads allowed)
			(copperpour allowed)
			(footprints allowed)
		)
		(placement
			(enabled no)
			(sheetname "")
		)
		(fill
			(thermal_gap 0.5)
			(thermal_bridge_width 0.5)
			(island_removal_mode 0)
		)
		(polygon
			(pts
				(xy 192.066926 -237.57636) (xy 194.098926 -237.57636) (xy 194.098926 -237.578646) (xy 194.277742 -237.578646)
				(xy 194.277742 -237.815882) (xy 194.458844 -237.996984) (xy 194.474338 -238.012478) (xy 194.474338 -238.201454)
				(xy 194.458844 -238.216948) (xy 194.347846 -238.327946) (xy 194.307206 -238.368586) (xy 191.845946 -238.368586)
				(xy 191.704722 -238.227362) (xy 191.704722 -238.030258) (xy 191.786256 -237.948724) (xy 191.845184 -237.889796)
				(xy 191.845184 -237.57636) (xy 191.883792 -237.57636) (xy 191.930782 -237.57636)
			)
		)
	)
	(zone
		(layer "F.Cu")
		(hatch none 0.5)
		(connect_pads
			(clearance 0)
		)
		(min_thickness 0.25)
		(keepout
			(tracks allowed)
			(vias allowed)
			(pads allowed)
			(copperpour allowed)
			(footprints not_allowed)
		)
		(placement
			(enabled no)
			(sheetname "")
		)
		(fill
			(thermal_gap 0.5)
			(thermal_bridge_width 0.5)
			(island_removal_mode 0)
		)
		(polygon
			(pts
				(xy 157.813502 -330.091796) (xy 163.913312 -330.091796) (xy 163.913312 -186.09183) (xy 157.813502 -186.09183)
			)
		)
	)
	(zone
		(layer "F.Cu")
		(hatch none 0.5)
		(connect_pads
			(clearance 0)
		)
		(min_thickness 0.25)
		(keepout
			(tracks allowed)
			(vias allowed)
			(pads allowed)
			(copperpour allowed)
			(footprints allowed)
		)
		(placement
			(enabled no)
			(sheetname "")
		)
		(fill
			(thermal_gap 0.5)
			(thermal_bridge_width 0.5)
			(island_removal_mode 0)
		)
		(polygon
			(pts
				(xy 84.853018 -259.323586) (xy 85.055964 -259.12064) (xy 85.055964 -259.07746) (xy 84.612226 -258.633722)
				(xy 84.490052 -258.633722) (xy 84.35721 -258.766818) (xy 84.35721 -258.870958) (xy 84.809838 -259.323586)
			)
		)
	)
	(zone
		(layer "F.Cu")
		(hatch none 0.5)
		(connect_pads
			(clearance 0)
		)
		(min_thickness 0.25)
		(keepout
			(tracks allowed)
			(vias allowed)
			(pads allowed)
			(copperpour allowed)
			(footprints allowed)
		)
		(placement
			(enabled no)
			(sheetname "")
		)
		(fill
			(thermal_gap 0.5)
			(thermal_bridge_width 0.5)
			(island_removal_mode 0)
		)
		(polygon
			(pts
				(xy 413.275526 -299.00499) (xy 413.275526 -298.77639) (xy 415.307526 -298.77639) (xy 415.307526 -299.00499)
			)
		)
	)
	(zone
		(layer "F.Cu")
		(hatch none 0.5)
		(connect_pads
			(clearance 0)
		)
		(min_thickness 0.25)
		(keepout
			(tracks allowed)
			(vias allowed)
			(pads allowed)
			(copperpour allowed)
			(footprints allowed)
		)
		(placement
			(enabled no)
			(sheetname "")
		)
		(fill
			(thermal_gap 0.5)
			(thermal_bridge_width 0.5)
			(island_removal_mode 0)
		)
		(polygon
			(pts
				(xy 138.75258 -221.811088) (xy 139.0396 -221.811088) (xy 139.07008 -221.780608) (xy 139.07008 -221.153228)
				(xy 138.98372 -221.066868) (xy 138.79576 -221.066868) (xy 138.7221 -221.140528) (xy 138.7221 -221.780608)
			)
		)
	)
	(zone
		(layer "F.Cu")
		(hatch none 0.5)
		(connect_pads
			(clearance 0)
		)
		(min_thickness 0.25)
		(keepout
			(tracks allowed)
			(vias allowed)
			(pads allowed)
			(copperpour allowed)
			(footprints allowed)
		)
		(placement
			(enabled no)
			(sheetname "")
		)
		(fill
			(thermal_gap 0.5)
			(thermal_bridge_width 0.5)
			(island_removal_mode 0)
		)
		(polygon
			(pts
				(xy 274.143978 -259.166614) (xy 274.143978 -258.722876) (xy 276.469094 -258.722876) (xy 276.469094 -259.166614)
			)
		)
	)
	(zone
		(layer "F.Cu")
		(hatch none 0.5)
		(connect_pads
			(clearance 0)
		)
		(min_thickness 0.25)
		(keepout
			(tracks allowed)
			(vias allowed)
			(pads allowed)
			(copperpour allowed)
			(footprints allowed)
		)
		(placement
			(enabled no)
			(sheetname "")
		)
		(fill
			(thermal_gap 0.5)
			(thermal_bridge_width 0.5)
			(island_removal_mode 0)
		)
		(polygon
			(pts
				(xy 424.919394 -219.107004) (xy 426.951394 -219.107004) (xy 426.951394 -218.878404) (xy 424.919394 -218.878404)
				(xy 424.788076 -218.878404) (xy 424.762168 -218.878404) (xy 424.762168 -219.107004) (xy 424.788076 -219.107004)
			)
		)
	)
	(zone
		(layer "F.Cu")
		(hatch none 0.5)
		(connect_pads
			(clearance 0)
		)
		(min_thickness 0.25)
		(keepout
			(tracks allowed)
			(vias allowed)
			(pads allowed)
			(copperpour allowed)
			(footprints allowed)
		)
		(placement
			(enabled no)
			(sheetname "")
		)
		(fill
			(thermal_gap 0.5)
			(thermal_bridge_width 0.5)
			(island_removal_mode 0)
		)
		(polygon
			(pts
				(xy 424.919394 -233.326432) (xy 426.951394 -233.326432) (xy 426.951394 -233.555032) (xy 424.919394 -233.555032)
				(xy 424.78325 -233.555032) (xy 424.73626 -233.555032) (xy 424.73626 -233.326432) (xy 424.78325 -233.326432)
			)
		)
	)
	(zone
		(layer "F.Cu")
		(hatch none 0.5)
		(connect_pads
			(clearance 0)
		)
		(min_thickness 0.25)
		(keepout
			(tracks allowed)
			(vias allowed)
			(pads allowed)
			(copperpour allowed)
			(footprints allowed)
		)
		(placement
			(enabled no)
			(sheetname "")
		)
		(fill
			(thermal_gap 0.5)
			(thermal_bridge_width 0.5)
			(island_removal_mode 0)
		)
		(polygon
			(pts
				(xy 157.791658 -197.00494) (xy 157.791658 -196.77634) (xy 159.823658 -196.77634) (xy 159.823658 -197.00494)
			)
		)
	)
	(zone
		(layer "F.Cu")
		(hatch none 0.5)
		(connect_pads
			(clearance 0)
		)
		(min_thickness 0.25)
		(keepout
			(tracks allowed)
			(vias allowed)
			(pads allowed)
			(copperpour allowed)
			(footprints allowed)
		)
		(placement
			(enabled no)
			(sheetname "")
		)
		(fill
			(thermal_gap 0.5)
			(thermal_bridge_width 0.5)
			(island_removal_mode 0)
		)
		(polygon
			(pts
				(xy 161.891726 -197.854824) (xy 161.891726 -197.626224) (xy 163.923726 -197.626224) (xy 163.923726 -197.854824)
			)
		)
	)
	(zone
		(layer "F.Cu")
		(hatch none 0.5)
		(connect_pads
			(clearance 0)
		)
		(min_thickness 0.25)
		(keepout
			(tracks allowed)
			(vias allowed)
			(pads allowed)
			(copperpour allowed)
			(footprints not_allowed)
		)
		(placement
			(enabled no)
			(sheetname "")
		)
		(fill
			(thermal_gap 0.5)
			(thermal_bridge_width 0.5)
			(island_removal_mode 0)
		)
		(polygon
			(pts
				(arc
					(start 2.999994 -344.518234)
					(mid 18.339672 -347.700092)
					(end 2.999994 -350.88195)
				)
			)
		)
	)
	(zone
		(layer "F.Cu")
		(hatch none 0.5)
		(connect_pads
			(clearance 0)
		)
		(min_thickness 0.25)
		(keepout
			(tracks allowed)
			(vias allowed)
			(pads allowed)
			(copperpour allowed)
			(footprints allowed)
		)
		(placement
			(enabled no)
			(sheetname "")
		)
		(fill
			(thermal_gap 0.5)
			(thermal_bridge_width 0.5)
			(island_removal_mode 0)
		)
		(polygon
			(pts
				(xy 44.735242 -231.116632) (xy 44.735242 -230.672894) (xy 47.060358 -230.672894) (xy 47.060358 -231.116632)
			)
		)
	)
	(zone
		(layer "F.Cu")
		(hatch none 0.5)
		(connect_pads
			(clearance 0)
		)
		(min_thickness 0.25)
		(keepout
			(tracks allowed)
			(vias allowed)
			(pads allowed)
			(copperpour allowed)
			(footprints allowed)
		)
		(placement
			(enabled no)
			(sheetname "")
		)
		(fill
			(thermal_gap 0.5)
			(thermal_bridge_width 0.5)
			(island_removal_mode 0)
		)
		(polygon
			(pts
				(xy 304.319178 -303.366424) (xy 304.319178 -302.922686) (xy 306.644294 -302.922686) (xy 306.644294 -303.366424)
			)
		)
	)
	(zone
		(layer "F.Cu")
		(hatch none 0.5)
		(connect_pads
			(clearance 0)
		)
		(min_thickness 0.25)
		(keepout
			(tracks allowed)
			(vias allowed)
			(pads allowed)
			(copperpour allowed)
			(footprints allowed)
		)
		(placement
			(enabled no)
			(sheetname "")
		)
		(fill
			(thermal_gap 0.5)
			(thermal_bridge_width 0.5)
			(island_removal_mode 0)
		)
		(polygon
			(pts
				(xy 311.91708 -260.866636) (xy 311.91708 -260.422898) (xy 314.12688 -260.422898) (xy 314.12688 -260.866636)
			)
		)
	)
	(zone
		(layer "F.Cu")
		(hatch none 0.5)
		(connect_pads
			(clearance 0)
		)
		(min_thickness 0.25)
		(keepout
			(tracks allowed)
			(vias allowed)
			(pads allowed)
			(copperpour allowed)
			(footprints allowed)
		)
		(placement
			(enabled no)
			(sheetname "")
		)
		(fill
			(thermal_gap 0.5)
			(thermal_bridge_width 0.5)
			(island_removal_mode 0)
		)
		(polygon
			(pts
				(xy 207.154526 -212.926422) (xy 209.186526 -212.926422) (xy 209.186526 -213.155022) (xy 207.154526 -213.155022)
				(xy 207.018382 -213.155022) (xy 206.971392 -213.155022) (xy 206.971392 -212.926422) (xy 207.018382 -212.926422)
			)
		)
	)
	(zone
		(layer "F.Cu")
		(hatch none 0.5)
		(connect_pads
			(clearance 0)
		)
		(min_thickness 0.25)
		(keepout
			(tracks allowed)
			(vias allowed)
			(pads allowed)
			(copperpour allowed)
			(footprints allowed)
		)
		(placement
			(enabled no)
			(sheetname "")
		)
		(fill
			(thermal_gap 0.5)
			(thermal_bridge_width 0.5)
			(island_removal_mode 0)
		)
		(polygon
			(pts
				(xy 44.735242 -311.866534) (xy 44.735242 -311.422796) (xy 47.060358 -311.422796) (xy 47.060358 -311.866534)
			)
		)
	)
	(zone
		(layer "F.Cu")
		(hatch none 0.5)
		(connect_pads
			(clearance 0)
		)
		(min_thickness 0.25)
		(keepout
			(tracks not_allowed)
			(vias allowed)
			(pads allowed)
			(copperpour not_allowed)
			(footprints allowed)
		)
		(placement
			(enabled no)
			(sheetname "")
		)
		(fill
			(thermal_gap 0.5)
			(thermal_bridge_width 0.5)
			(island_removal_mode 0)
		)
		(polygon
			(pts
				(xy 119.434864 -335.753456) (xy 119.67718 -335.753456) (xy 119.67718 -335.686908) (xy 119.434864 -335.686908)
			)
		)
	)
	(zone
		(layer "F.Cu")
		(hatch none 0.5)
		(connect_pads
			(clearance 0)
		)
		(min_thickness 0.25)
		(keepout
			(tracks allowed)
			(vias allowed)
			(pads allowed)
			(copperpour allowed)
			(footprints allowed)
		)
		(placement
			(enabled no)
			(sheetname "")
		)
		(fill
			(thermal_gap 0.5)
			(thermal_bridge_width 0.5)
			(island_removal_mode 0)
		)
		(polygon
			(pts
				(xy 304.319178 -272.322798) (xy 306.644294 -272.322798) (xy 306.911756 -272.322798) (xy 306.911756 -273.26463)
				(xy 303.984406 -273.26463) (xy 303.984406 -272.322798)
			)
		)
	)
	(zone
		(layer "F.Cu")
		(hatch none 0.5)
		(connect_pads
			(clearance 0)
		)
		(min_thickness 0.25)
		(keepout
			(tracks allowed)
			(vias allowed)
			(pads allowed)
			(copperpour allowed)
			(footprints allowed)
		)
		(placement
			(enabled no)
			(sheetname "")
		)
		(fill
			(thermal_gap 0.5)
			(thermal_bridge_width 0.5)
			(island_removal_mode 0)
		)
		(polygon
			(pts
				(xy 383.20726 -340.890352) (xy 383.20726 -344.895932) (xy 383.68732 -345.375992) (xy 385.75234 -345.375992)
				(xy 386.02412 -345.104212) (xy 386.02412 -343.250012) (xy 386.27558 -342.998552) (xy 388.19582 -342.998552)
				(xy 388.61238 -342.581992) (xy 388.61238 -341.091012) (xy 387.96468 -340.443312) (xy 383.6543 -340.443312)
			)
		)
	)
	(zone
		(layer "F.Cu")
		(hatch none 0.5)
		(connect_pads
			(clearance 0)
		)
		(min_thickness 0.25)
		(keepout
			(tracks allowed)
			(vias allowed)
			(pads allowed)
			(copperpour allowed)
			(footprints not_allowed)
		)
		(placement
			(enabled no)
			(sheetname "")
		)
		(fill
			(thermal_gap 0.5)
			(thermal_bridge_width 0.5)
			(island_removal_mode 0)
		)
		(polygon
			(pts
				(xy 307.88737 -330.091796) (xy 313.98718 -330.091796) (xy 313.98718 -186.09183) (xy 307.88737 -186.09183)
			)
		)
	)
	(zone
		(layer "F.Cu")
		(hatch none 0.5)
		(connect_pads
			(clearance 0)
		)
		(min_thickness 0.25)
		(keepout
			(tracks allowed)
			(vias allowed)
			(pads allowed)
			(copperpour allowed)
			(footprints allowed)
		)
		(placement
			(enabled no)
			(sheetname "")
		)
		(fill
			(thermal_gap 0.5)
			(thermal_bridge_width 0.5)
			(island_removal_mode 0)
		)
		(polygon
			(pts
				(xy 195.510658 -306.654962) (xy 195.510658 -306.426362) (xy 197.542658 -306.426362) (xy 197.542658 -306.654962)
			)
		)
	)
	(zone
		(layer "F.Cu")
		(hatch none 0.5)
		(connect_pads
			(clearance 0)
		)
		(min_thickness 0.25)
		(keepout
			(tracks allowed)
			(vias allowed)
			(pads allowed)
			(copperpour allowed)
			(footprints allowed)
		)
		(placement
			(enabled no)
			(sheetname "")
		)
		(fill
			(thermal_gap 0.5)
			(thermal_bridge_width 0.5)
			(island_removal_mode 0)
		)
		(polygon
			(pts
				(xy 14.560042 -206.46644) (xy 14.560042 -206.022702) (xy 16.885158 -206.022702) (xy 16.885158 -206.46644)
			)
		)
	)
	(zone
		(layer "F.Cu")
		(hatch none 0.5)
		(connect_pads
			(clearance 0)
		)
		(min_thickness 0.25)
		(keepout
			(tracks allowed)
			(vias allowed)
			(pads allowed)
			(copperpour allowed)
			(footprints not_allowed)
		)
		(placement
			(enabled no)
			(sheetname "")
		)
		(fill
			(thermal_gap 0.5)
			(thermal_bridge_width 0.5)
			(island_removal_mode 0)
		)
		(polygon
			(pts
				(xy 413.29737 -330.091796) (xy 419.39718 -330.091796) (xy 419.39718 -186.09183) (xy 413.29737 -186.09183)
			)
		)
	)
	(zone
		(layer "F.Cu")
		(hatch none 0.5)
		(connect_pads
			(clearance 0)
		)
		(min_thickness 0.25)
		(keepout
			(tracks allowed)
			(vias allowed)
			(pads allowed)
			(copperpour allowed)
			(footprints allowed)
		)
		(placement
			(enabled no)
			(sheetname "")
		)
		(fill
			(thermal_gap 0.5)
			(thermal_bridge_width 0.5)
			(island_removal_mode 0)
		)
		(polygon
			(pts
				(xy 428.363126 -304.95494) (xy 428.363126 -304.72634) (xy 430.395126 -304.72634) (xy 430.395126 -304.95494)
			)
		)
	)
	(zone
		(layer "F.Cu")
		(hatch none 0.5)
		(connect_pads
			(clearance 0)
		)
		(min_thickness 0.25)
		(keepout
			(tracks allowed)
			(vias allowed)
			(pads allowed)
			(copperpour allowed)
			(footprints allowed)
		)
		(placement
			(enabled no)
			(sheetname "")
		)
		(fill
			(thermal_gap 0.5)
			(thermal_bridge_width 0.5)
			(island_removal_mode 0)
		)
		(polygon
			(pts
				(xy 176.979326 -222.276416) (xy 179.011326 -222.276416) (xy 179.011326 -222.505016) (xy 176.979326 -222.505016)
				(xy 176.843182 -222.505016) (xy 176.796192 -222.505016) (xy 176.796192 -222.276416) (xy 176.843182 -222.276416)
			)
		)
	)
	(zone
		(layer "F.Cu")
		(hatch none 0.5)
		(connect_pads
			(clearance 0)
		)
		(min_thickness 0.25)
		(keepout
			(tracks allowed)
			(vias allowed)
			(pads allowed)
			(copperpour allowed)
			(footprints allowed)
		)
		(placement
			(enabled no)
			(sheetname "")
		)
		(fill
			(thermal_gap 0.5)
			(thermal_bridge_width 0.5)
			(island_removal_mode 0)
		)
		(polygon
			(pts
				(xy 59.822842 -261.71652) (xy 59.822842 -261.272782) (xy 62.147958 -261.272782) (xy 62.147958 -261.71652)
			)
		)
	)
	(zone
		(layer "F.Cu")
		(hatch none 0.5)
		(connect_pads
			(clearance 0)
		)
		(min_thickness 0.25)
		(keepout
			(tracks allowed)
			(vias allowed)
			(pads allowed)
			(copperpour allowed)
			(footprints allowed)
		)
		(placement
			(enabled no)
			(sheetname "")
		)
		(fill
			(thermal_gap 0.5)
			(thermal_bridge_width 0.5)
			(island_removal_mode 0)
		)
		(polygon
			(pts
				(xy 14.560042 -286.366458) (xy 14.560042 -285.92272) (xy 16.885158 -285.92272) (xy 16.885158 -286.366458)
			)
		)
	)
	(zone
		(layer "F.Cu")
		(hatch none 0.5)
		(connect_pads
			(clearance 0)
		)
		(min_thickness 0.25)
		(keepout
			(tracks allowed)
			(vias allowed)
			(pads allowed)
			(copperpour allowed)
			(footprints allowed)
		)
		(placement
			(enabled no)
			(sheetname "")
		)
		(fill
			(thermal_gap 0.5)
			(thermal_bridge_width 0.5)
			(island_removal_mode 0)
		)
		(polygon
			(pts
				(xy 259.056378 -271.066514) (xy 259.056378 -270.622776) (xy 261.381494 -270.622776) (xy 261.381494 -271.066514)
			)
		)
	)
	(zone
		(layer "F.Cu")
		(hatch none 0.5)
		(connect_pads
			(clearance 0)
		)
		(min_thickness 0.25)
		(keepout
			(tracks allowed)
			(vias allowed)
			(pads allowed)
			(copperpour allowed)
			(footprints allowed)
		)
		(placement
			(enabled no)
			(sheetname "")
		)
		(fill
			(thermal_gap 0.5)
			(thermal_bridge_width 0.5)
			(island_removal_mode 0)
		)
		(polygon
			(pts
				(xy 64.002412 -201.366628) (xy 64.002412 -200.92289) (xy 66.212212 -200.92289) (xy 66.212212 -201.366628)
			)
		)
	)
	(zone
		(layer "F.Cu")
		(hatch none 0.5)
		(connect_pads
			(clearance 0)
		)
		(min_thickness 0.25)
		(keepout
			(tracks allowed)
			(vias allowed)
			(pads allowed)
			(copperpour allowed)
			(footprints not_allowed)
		)
		(placement
			(enabled no)
			(sheetname "")
		)
		(fill
			(thermal_gap 0.5)
			(thermal_bridge_width 0.5)
			(island_removal_mode 0)
		)
		(polygon
			(pts
				(arc
					(start 209.64525 -51.999896)
					(mid 204.64526 -56.999886)
					(end 199.64527 -51.999896)
				)
				(arc
					(start 199.64527 -51.999896)
					(mid 204.64526 -46.999906)
					(end 209.64525 -51.999896)
				)
			)
		)
	)
	(zone
		(layer "F.Cu")
		(hatch none 0.5)
		(connect_pads
			(clearance 0)
		)
		(min_thickness 0.25)
		(keepout
			(tracks allowed)
			(vias allowed)
			(pads allowed)
			(copperpour allowed)
			(footprints allowed)
		)
		(placement
			(enabled no)
			(sheetname "")
		)
		(fill
			(thermal_gap 0.5)
			(thermal_bridge_width 0.5)
			(island_removal_mode 0)
		)
		(polygon
			(pts
				(xy 48.0568 -358.943148) (xy 48.0568 -355.928168) (xy 53.4543 -355.928168) (xy 53.4543 -358.943148)
			)
		)
	)
	(zone
		(layer "F.Cu")
		(hatch none 0.5)
		(connect_pads
			(clearance 0)
		)
		(min_thickness 0.25)
		(keepout
			(tracks allowed)
			(vias allowed)
			(pads allowed)
			(copperpour allowed)
			(footprints allowed)
		)
		(placement
			(enabled no)
			(sheetname "")
		)
		(fill
			(thermal_gap 0.5)
			(thermal_bridge_width 0.5)
			(island_removal_mode 0)
		)
		(polygon
			(pts
				(xy 134.8232 -15.357348) (xy 134.8232 -14.125448) (xy 137.48512 -14.125448) (xy 137.48512 -15.357348)
			)
		)
	)
	(zone
		(layer "F.Cu")
		(hatch none 0.5)
		(connect_pads
			(clearance 0)
		)
		(min_thickness 0.25)
		(keepout
			(tracks allowed)
			(vias allowed)
			(pads allowed)
			(copperpour allowed)
			(footprints allowed)
		)
		(placement
			(enabled no)
			(sheetname "")
		)
		(fill
			(thermal_gap 0.5)
			(thermal_bridge_width 0.5)
			(island_removal_mode 0)
		)
		(polygon
			(pts
				(xy 41.29151 -248.966482) (xy 41.29151 -248.522744) (xy 43.616626 -248.522744) (xy 43.616626 -248.966482)
			)
		)
	)
	(zone
		(layer "F.Cu")
		(hatch none 0.5)
		(connect_pads
			(clearance 0)
		)
		(min_thickness 0.25)
		(keepout
			(tracks allowed)
			(vias allowed)
			(pads allowed)
			(copperpour allowed)
			(footprints allowed)
		)
		(placement
			(enabled no)
			(sheetname "")
		)
		(fill
			(thermal_gap 0.5)
			(thermal_bridge_width 0.5)
			(island_removal_mode 0)
		)
		(polygon
			(pts
				(xy 289.231578 -294.01643) (xy 289.231578 -293.572692) (xy 291.556694 -293.572692) (xy 291.556694 -294.01643)
			)
		)
	)
	(zone
		(layer "F.Cu")
		(hatch none 0.5)
		(connect_pads
			(clearance 0)
		)
		(min_thickness 0.25)
		(keepout
			(tracks allowed)
			(vias allowed)
			(pads allowed)
			(copperpour allowed)
			(footprints allowed)
		)
		(placement
			(enabled no)
			(sheetname "")
		)
		(fill
			(thermal_gap 0.5)
			(thermal_bridge_width 0.5)
			(island_removal_mode 0)
		)
		(polygon
			(pts
				(xy 274.143978 -248.966482) (xy 274.143978 -248.522744) (xy 276.469094 -248.522744) (xy 276.469094 -248.966482)
			)
		)
	)
	(zone
		(layer "F.Cu")
		(hatch none 0.5)
		(connect_pads
			(clearance 0)
		)
		(min_thickness 0.25)
		(keepout
			(tracks allowed)
			(vias allowed)
			(pads allowed)
			(copperpour allowed)
			(footprints allowed)
		)
		(placement
			(enabled no)
			(sheetname "")
		)
		(fill
			(thermal_gap 0.5)
			(thermal_bridge_width 0.5)
			(island_removal_mode 0)
		)
		(polygon
			(pts
				(xy 409.831794 -245.454932) (xy 409.831794 -245.226332) (xy 411.863794 -245.226332) (xy 411.863794 -245.454932)
			)
		)
	)
	(zone
		(layer "F.Cu")
		(hatch none 0.5)
		(connect_pads
			(clearance 0)
		)
		(min_thickness 0.25)
		(keepout
			(tracks allowed)
			(vias allowed)
			(pads allowed)
			(copperpour allowed)
			(footprints allowed)
		)
		(placement
			(enabled no)
			(sheetname "")
		)
		(fill
			(thermal_gap 0.5)
			(thermal_bridge_width 0.5)
			(island_removal_mode 0)
		)
		(polygon
			(pts
				(xy 307.76291 -290.61664) (xy 307.76291 -290.172902) (xy 310.088026 -290.172902) (xy 310.088026 -290.61664)
			)
		)
	)
	(zone
		(layer "F.Cu")
		(hatch none 0.5)
		(connect_pads
			(clearance 0)
		)
		(min_thickness 0.25)
		(keepout
			(tracks allowed)
			(vias allowed)
			(pads allowed)
			(copperpour allowed)
			(footprints allowed)
		)
		(placement
			(enabled no)
			(sheetname "")
		)
		(fill
			(thermal_gap 0.5)
			(thermal_bridge_width 0.5)
			(island_removal_mode 0)
		)
		(polygon
			(pts
				(xy 440.006994 -220.576394) (xy 442.038994 -220.576394) (xy 442.038994 -220.804994) (xy 440.006994 -220.804994)
				(xy 439.87085 -220.804994) (xy 439.82386 -220.804994) (xy 439.82386 -220.576394) (xy 439.87085 -220.576394)
			)
		)
	)
	(zone
		(layer "F.Cu")
		(hatch none 0.5)
		(connect_pads
			(clearance 0)
		)
		(min_thickness 0.25)
		(keepout
			(tracks allowed)
			(vias allowed)
			(pads allowed)
			(copperpour allowed)
			(footprints allowed)
		)
		(placement
			(enabled no)
			(sheetname "")
		)
		(fill
			(thermal_gap 0.5)
			(thermal_bridge_width 0.5)
			(island_removal_mode 0)
		)
		(polygon
			(pts
				(xy 400.708368 -18.55978) (xy 400.708368 -15.425166) (xy 402.48713 -15.425166) (xy 402.48713 -18.55978)
			)
		)
	)
	(zone
		(layer "F.Cu")
		(hatch none 0.5)
		(connect_pads
			(clearance 0)
		)
		(min_thickness 0.25)
		(keepout
			(tracks allowed)
			(vias allowed)
			(pads allowed)
			(copperpour allowed)
			(footprints not_allowed)
		)
		(placement
			(enabled no)
			(sheetname "")
		)
		(fill
			(thermal_gap 0.5)
			(thermal_bridge_width 0.5)
			(island_removal_mode 0)
		)
		(polygon
			(pts
				(xy 248.630694 -344.084656) (xy 248.630694 -347.521784) (xy 320.437256 -347.521784) (xy 320.437256 -328.521822)
				(xy 314.987178 -328.521822) (xy 314.987178 -331.091794) (xy 254.130048 -331.091794) (xy 254.130048 -344.084656)
			)
		)
	)
	(zone
		(layer "F.Cu")
		(hatch none 0.5)
		(connect_pads
			(clearance 0)
		)
		(min_thickness 0.25)
		(keepout
			(tracks allowed)
			(vias allowed)
			(pads allowed)
			(copperpour allowed)
			(footprints allowed)
		)
		(placement
			(enabled no)
			(sheetname "")
		)
		(fill
			(thermal_gap 0.5)
			(thermal_bridge_width 0.5)
			(island_removal_mode 0)
		)
		(polygon
			(pts
				(xy 20.16506 -5.857748) (xy 20.16506 -3.957828) (xy 22.37232 -3.957828) (xy 22.37232 -5.857748)
			)
		)
	)
	(zone
		(layer "F.Cu")
		(hatch none 0.5)
		(connect_pads
			(clearance 0)
		)
		(min_thickness 0.25)
		(keepout
			(tracks allowed)
			(vias allowed)
			(pads allowed)
			(copperpour allowed)
			(footprints not_allowed)
		)
		(placement
			(enabled no)
			(sheetname "")
		)
		(fill
			(thermal_gap 0.5)
			(thermal_bridge_width 0.5)
			(island_removal_mode 0)
		)
		(polygon
			(pts
				(xy 469.122252 -79.76362) (xy 437.302656 -79.76362) (xy 437.302148 -82.763614)
				(arc
					(start 467.300818 -82.763614)
					(mid 467.540995 -81.650588)
					(end 468.178642 -80.70723)
				)
			)
		)
	)
	(zone
		(layer "F.Cu")
		(hatch none 0.5)
		(connect_pads
			(clearance 0)
		)
		(min_thickness 0.25)
		(keepout
			(tracks allowed)
			(vias allowed)
			(pads allowed)
			(copperpour allowed)
			(footprints allowed)
		)
		(placement
			(enabled no)
			(sheetname "")
		)
		(fill
			(thermal_gap 0.5)
			(thermal_bridge_width 0.5)
			(island_removal_mode 0)
		)
		(polygon
			(pts
				(xy 165.335458 -244.376194) (xy 167.367458 -244.376194) (xy 167.367458 -244.604794) (xy 165.335458 -244.604794)
				(xy 165.141656 -244.604794) (xy 165.141656 -244.376194)
			)
		)
	)
	(zone
		(layer "F.Cu")
		(hatch none 0.5)
		(connect_pads
			(clearance 0)
		)
		(min_thickness 0.25)
		(keepout
			(tracks allowed)
			(vias allowed)
			(pads allowed)
			(copperpour allowed)
			(footprints allowed)
		)
		(placement
			(enabled no)
			(sheetname "")
		)
		(fill
			(thermal_gap 0.5)
			(thermal_bridge_width 0.5)
			(island_removal_mode 0)
		)
		(polygon
			(pts
				(xy 424.919394 -270.726408) (xy 426.951394 -270.726408) (xy 426.951394 -270.955008) (xy 424.919394 -270.955008)
				(xy 424.78325 -270.955008) (xy 424.73626 -270.955008) (xy 424.73626 -270.726408) (xy 424.78325 -270.726408)
			)
		)
	)
	(zone
		(layer "F.Cu")
		(hatch none 0.5)
		(connect_pads
			(clearance 0)
		)
		(min_thickness 0.25)
		(keepout
			(tracks allowed)
			(vias allowed)
			(pads allowed)
			(copperpour allowed)
			(footprints allowed)
		)
		(placement
			(enabled no)
			(sheetname "")
		)
		(fill
			(thermal_gap 0.5)
			(thermal_bridge_width 0.5)
			(island_removal_mode 0)
		)
		(polygon
			(pts
				(xy 144.203928 -404.802594) (xy 144.203928 -399.959576) (xy 146.088354 -399.959576) (xy 146.088354 -404.802594)
			)
		)
	)
	(zone
		(layer "F.Cu")
		(hatch none 0.5)
		(connect_pads
			(clearance 0)
		)
		(min_thickness 0.25)
		(keepout
			(tracks allowed)
			(vias allowed)
			(pads allowed)
			(copperpour allowed)
			(footprints allowed)
		)
		(placement
			(enabled no)
			(sheetname "")
		)
		(fill
			(thermal_gap 0.5)
			(thermal_bridge_width 0.5)
			(island_removal_mode 0)
		)
		(polygon
			(pts
				(xy 184.350914 -353.424744) (xy 180.815234 -353.424744) (xy 180.815234 -351.341944) (xy 184.350914 -351.341944)
			)
		)
	)
	(zone
		(layer "F.Cu")
		(hatch none 0.5)
		(connect_pads
			(clearance 0)
		)
		(min_thickness 0.25)
		(keepout
			(tracks not_allowed)
			(vias allowed)
			(pads allowed)
			(copperpour not_allowed)
			(footprints allowed)
		)
		(placement
			(enabled no)
			(sheetname "")
		)
		(fill
			(thermal_gap 0.5)
			(thermal_bridge_width 0.5)
			(island_removal_mode 0)
		)
		(polygon
			(pts
				(xy 439.368946 -9.0424) (xy 439.544206 -9.0424) (xy 439.572146 -9.01446) (xy 439.572146 -7.62) (xy 439.549286 -7.59714)
				(xy 439.379106 -7.59714) (xy 439.358786 -7.61746) (xy 439.358786 -9.03224)
			)
		)
	)
	(zone
		(layer "F.Cu")
		(hatch none 0.5)
		(connect_pads
			(clearance 0)
		)
		(min_thickness 0.25)
		(keepout
			(tracks allowed)
			(vias allowed)
			(pads allowed)
			(copperpour allowed)
			(footprints allowed)
		)
		(placement
			(enabled no)
			(sheetname "")
		)
		(fill
			(thermal_gap 0.5)
			(thermal_bridge_width 0.5)
			(island_removal_mode 0)
		)
		(polygon
			(pts
				(xy 406.296368 -18.55978) (xy 406.296368 -15.425166) (xy 408.07513 -15.425166) (xy 408.07513 -18.55978)
			)
		)
	)
	(zone
		(layer "F.Cu")
		(hatch none 0.5)
		(connect_pads
			(clearance 0)
		)
		(min_thickness 0.25)
		(keepout
			(tracks allowed)
			(vias allowed)
			(pads allowed)
			(copperpour allowed)
			(footprints allowed)
		)
		(placement
			(enabled no)
			(sheetname "")
		)
		(fill
			(thermal_gap 0.5)
			(thermal_bridge_width 0.5)
			(island_removal_mode 0)
		)
		(polygon
			(pts
				(xy 405.731726 -261.605014) (xy 405.731726 -261.376414) (xy 407.763726 -261.376414) (xy 407.763726 -261.605014)
			)
		)
	)
	(zone
		(layer "F.Cu")
		(hatch none 0.5)
		(connect_pads
			(clearance 0)
		)
		(min_thickness 0.25)
		(keepout
			(tracks allowed)
			(vias allowed)
			(pads allowed)
			(copperpour allowed)
			(footprints allowed)
		)
		(placement
			(enabled no)
			(sheetname "")
		)
		(fill
			(thermal_gap 0.5)
			(thermal_bridge_width 0.5)
			(island_removal_mode 0)
		)
		(polygon
			(pts
				(xy 289.231578 -196.266562) (xy 289.231578 -195.822824) (xy 291.556694 -195.822824) (xy 291.556694 -196.266562)
			)
		)
	)
	(zone
		(layer "F.Cu")
		(hatch none 0.5)
		(connect_pads
			(clearance 0)
		)
		(min_thickness 0.25)
		(keepout
			(tracks allowed)
			(vias allowed)
			(pads allowed)
			(copperpour allowed)
			(footprints allowed)
		)
		(placement
			(enabled no)
			(sheetname "")
		)
		(fill
			(thermal_gap 0.5)
			(thermal_bridge_width 0.5)
			(island_removal_mode 0)
		)
		(polygon
			(pts
				(xy 210.598258 -278.60498) (xy 210.598258 -278.37638) (xy 212.630258 -278.37638) (xy 212.630258 -278.60498)
			)
		)
	)
	(zone
		(layer "F.Cu")
		(hatch none 0.5)
		(connect_pads
			(clearance 0)
		)
		(min_thickness 0.25)
		(keepout
			(tracks allowed)
			(vias allowed)
			(pads allowed)
			(copperpour allowed)
			(footprints allowed)
		)
		(placement
			(enabled no)
			(sheetname "")
		)
		(fill
			(thermal_gap 0.5)
			(thermal_bridge_width 0.5)
			(island_removal_mode 0)
		)
		(polygon
			(pts
				(xy 303.523142 -404.802594) (xy 303.523142 -399.959576) (xy 305.407568 -399.959576) (xy 305.407568 -404.802594)
			)
		)
	)
	(zone
		(layer "F.Cu")
		(hatch none 0.5)
		(connect_pads
			(clearance 0)
		)
		(min_thickness 0.25)
		(keepout
			(tracks not_allowed)
			(vias allowed)
			(pads allowed)
			(copperpour not_allowed)
			(footprints allowed)
		)
		(placement
			(enabled no)
			(sheetname "")
		)
		(fill
			(thermal_gap 0.5)
			(thermal_bridge_width 0.5)
			(island_removal_mode 0)
		)
		(polygon
			(pts
				(arc
					(start 94.383098 -50.249836)
					(mid 97.58299 -47.049944)
					(end 94.383098 -43.850052)
				)
				(arc
					(start 92.782898 -43.850052)
					(mid 89.583006 -47.049944)
					(end 92.782898 -50.249836)
				)
			)
		)
	)
	(zone
		(layer "F.Cu")
		(hatch none 0.5)
		(connect_pads
			(clearance 0)
		)
		(min_thickness 0.25)
		(keepout
			(tracks allowed)
			(vias allowed)
			(pads allowed)
			(copperpour allowed)
			(footprints allowed)
		)
		(placement
			(enabled no)
			(sheetname "")
		)
		(fill
			(thermal_gap 0.5)
			(thermal_bridge_width 0.5)
			(island_removal_mode 0)
		)
		(polygon
			(pts
				(xy 44.735242 -203.06665) (xy 44.735242 -202.622912) (xy 47.060358 -202.622912) (xy 47.060358 -203.06665)
			)
		)
	)
	(zone
		(layer "F.Cu")
		(hatch none 0.5)
		(connect_pads
			(clearance 0)
		)
		(min_thickness 0.25)
		(keepout
			(tracks allowed)
			(vias allowed)
			(pads allowed)
			(copperpour allowed)
			(footprints allowed)
		)
		(placement
			(enabled no)
			(sheetname "")
		)
		(fill
			(thermal_gap 0.5)
			(thermal_bridge_width 0.5)
			(island_removal_mode 0)
		)
		(polygon
			(pts
				(xy 304.319178 -220.9165) (xy 304.319178 -220.472762) (xy 306.644294 -220.472762) (xy 306.644294 -220.9165)
			)
		)
	)
	(zone
		(layer "F.Cu")
		(hatch none 0.5)
		(connect_pads
			(clearance 0)
		)
		(min_thickness 0.25)
		(keepout
			(tracks allowed)
			(vias allowed)
			(pads allowed)
			(copperpour allowed)
			(footprints allowed)
		)
		(placement
			(enabled no)
			(sheetname "")
		)
		(fill
			(thermal_gap 0.5)
			(thermal_bridge_width 0.5)
			(island_removal_mode 0)
		)
		(polygon
			(pts
				(xy 195.510658 -222.505016) (xy 195.510658 -222.276416) (xy 197.542658 -222.276416) (xy 197.542658 -222.505016)
			)
		)
	)
	(zone
		(layer "F.Cu")
		(hatch none 0.5)
		(connect_pads
			(clearance 0)
		)
		(min_thickness 0.25)
		(keepout
			(tracks allowed)
			(vias allowed)
			(pads allowed)
			(copperpour allowed)
			(footprints allowed)
		)
		(placement
			(enabled no)
			(sheetname "")
		)
		(fill
			(thermal_gap 0.5)
			(thermal_bridge_width 0.5)
			(island_removal_mode 0)
		)
		(polygon
			(pts
				(xy 180.423058 -311.755028) (xy 180.423058 -311.526428) (xy 182.455058 -311.526428) (xy 182.455058 -311.755028)
			)
		)
	)
	(zone
		(layer "F.Cu")
		(hatch none 0.5)
		(connect_pads
			(clearance 0)
		)
		(min_thickness 0.25)
		(keepout
			(tracks allowed)
			(vias allowed)
			(pads allowed)
			(copperpour allowed)
			(footprints allowed)
		)
		(placement
			(enabled no)
			(sheetname "")
		)
		(fill
			(thermal_gap 0.5)
			(thermal_bridge_width 0.5)
			(island_removal_mode 0)
		)
		(polygon
			(pts
				(xy 383.9972 -288.224468) (xy 384.28422 -288.224468) (xy 384.3147 -288.193988) (xy 384.3147 -287.566608)
				(xy 384.22834 -287.480248) (xy 384.04038 -287.480248) (xy 383.96672 -287.553908) (xy 383.96672 -288.193988)
			)
		)
	)
	(zone
		(layer "F.Cu")
		(hatch none 0.5)
		(connect_pads
			(clearance 0)
		)
		(min_thickness 0.25)
		(keepout
			(tracks allowed)
			(vias allowed)
			(pads allowed)
			(copperpour allowed)
			(footprints not_allowed)
		)
		(placement
			(enabled no)
			(sheetname "")
		)
		(fill
			(thermal_gap 0.5)
			(thermal_bridge_width 0.5)
			(island_removal_mode 0)
		)
		(polygon
			(pts
				(xy 267.393928 -161.289492) (xy 288.393886 -161.291524) (xy 288.396426 -139.291568) (xy 267.396214 -139.289282)
			)
		)
	)
	(zone
		(layer "F.Cu")
		(hatch none 0.5)
		(connect_pads
			(clearance 0)
		)
		(min_thickness 0.25)
		(keepout
			(tracks allowed)
			(vias allowed)
			(pads allowed)
			(copperpour allowed)
			(footprints allowed)
		)
		(placement
			(enabled no)
			(sheetname "")
		)
		(fill
			(thermal_gap 0.5)
			(thermal_bridge_width 0.5)
			(island_removal_mode 0)
		)
		(polygon
			(pts
				(xy 332.227936 -222.813372) (xy 332.430882 -223.016318) (xy 332.473808 -223.016318) (xy 332.917546 -222.572834)
				(xy 332.917546 -222.45066) (xy 332.784704 -222.317564) (xy 332.680564 -222.317564) (xy 332.227936 -222.770192)
			)
		)
	)
	(zone
		(layer "F.Cu")
		(hatch none 0.5)
		(connect_pads
			(clearance 0)
		)
		(min_thickness 0.25)
		(keepout
			(tracks allowed)
			(vias allowed)
			(pads allowed)
			(copperpour allowed)
			(footprints allowed)
		)
		(placement
			(enabled no)
			(sheetname "")
		)
		(fill
			(thermal_gap 0.5)
			(thermal_bridge_width 0.5)
			(island_removal_mode 0)
		)
		(polygon
			(pts
				(xy 165.335458 -240.126266) (xy 167.367458 -240.126266) (xy 167.549068 -240.126266) (xy 167.549068 -240.905284)
				(xy 165.158674 -240.905284) (xy 165.158674 -240.126266)
			)
		)
	)
	(zone
		(layer "F.Cu")
		(hatch none 0.5)
		(connect_pads
			(clearance 0)
		)
		(min_thickness 0.25)
		(keepout
			(tracks allowed)
			(vias allowed)
			(pads allowed)
			(copperpour allowed)
			(footprints allowed)
		)
		(placement
			(enabled no)
			(sheetname "")
		)
		(fill
			(thermal_gap 0.5)
			(thermal_bridge_width 0.5)
			(island_removal_mode 0)
		)
		(polygon
			(pts
				(xy 56.37911 -219.216478) (xy 56.37911 -218.77274) (xy 58.704226 -218.77274) (xy 58.704226 -219.216478)
			)
		)
	)
	(zone
		(layer "F.Cu")
		(hatch none 0.5)
		(connect_pads
			(clearance 0)
		)
		(min_thickness 0.25)
		(keepout
			(tracks allowed)
			(vias allowed)
			(pads allowed)
			(copperpour allowed)
			(footprints allowed)
		)
		(placement
			(enabled no)
			(sheetname "")
		)
		(fill
			(thermal_gap 0.5)
			(thermal_bridge_width 0.5)
			(island_removal_mode 0)
		)
		(polygon
			(pts
				(xy 428.363126 -241.205004) (xy 428.363126 -240.976404) (xy 430.395126 -240.976404) (xy 430.395126 -241.205004)
			)
		)
	)
	(zone
		(layer "F.Cu")
		(hatch none 0.5)
		(connect_pads
			(clearance 0)
		)
		(min_thickness 0.25)
		(keepout
			(tracks allowed)
			(vias allowed)
			(pads allowed)
			(copperpour allowed)
			(footprints allowed)
		)
		(placement
			(enabled no)
			(sheetname "")
		)
		(fill
			(thermal_gap 0.5)
			(thermal_bridge_width 0.5)
			(island_removal_mode 0)
		)
		(polygon
			(pts
				(xy 59.822842 -266.816586) (xy 59.822842 -266.372848) (xy 62.147958 -266.372848) (xy 62.147958 -266.816586)
			)
		)
	)
	(zone
		(layer "F.Cu")
		(hatch none 0.5)
		(connect_pads
			(clearance 0)
		)
		(min_thickness 0.25)
		(keepout
			(tracks allowed)
			(vias allowed)
			(pads allowed)
			(copperpour allowed)
			(footprints allowed)
		)
		(placement
			(enabled no)
			(sheetname "")
		)
		(fill
			(thermal_gap 0.5)
			(thermal_bridge_width 0.5)
			(island_removal_mode 0)
		)
		(polygon
			(pts
				(xy 289.231578 -197.966584) (xy 289.231578 -197.522846) (xy 291.556694 -197.522846) (xy 291.556694 -197.966584)
			)
		)
	)
	(zone
		(layer "F.Cu")
		(hatch none 0.5)
		(connect_pads
			(clearance 0)
		)
		(min_thickness 0.25)
		(keepout
			(tracks allowed)
			(vias allowed)
			(pads allowed)
			(copperpour allowed)
			(footprints allowed)
		)
		(placement
			(enabled no)
			(sheetname "")
		)
		(fill
			(thermal_gap 0.5)
			(thermal_bridge_width 0.5)
			(island_removal_mode 0)
		)
		(polygon
			(pts
				(xy 11.11631 -209.866484) (xy 11.11631 -209.422746) (xy 13.441426 -209.422746) (xy 13.441426 -209.866484)
			)
		)
	)
	(zone
		(layer "F.Cu")
		(hatch none 0.5)
		(connect_pads
			(clearance 0)
		)
		(min_thickness 0.25)
		(keepout
			(tracks allowed)
			(vias allowed)
			(pads allowed)
			(copperpour allowed)
			(footprints allowed)
		)
		(placement
			(enabled no)
			(sheetname "")
		)
		(fill
			(thermal_gap 0.5)
			(thermal_bridge_width 0.5)
			(island_removal_mode 0)
		)
		(polygon
			(pts
				(xy 332.835504 -265.785092) (xy 333.03845 -265.582146) (xy 333.03845 -265.53922) (xy 332.594966 -265.095482)
				(xy 332.472792 -265.095482) (xy 332.339696 -265.228324) (xy 332.339696 -265.332464) (xy 332.792324 -265.785092)
			)
		)
	)
	(zone
		(layer "F.Cu")
		(hatch none 0.5)
		(connect_pads
			(clearance 0)
		)
		(min_thickness 0.25)
		(keepout
			(tracks allowed)
			(vias allowed)
			(pads allowed)
			(copperpour allowed)
			(footprints allowed)
		)
		(placement
			(enabled no)
			(sheetname "")
		)
		(fill
			(thermal_gap 0.5)
			(thermal_bridge_width 0.5)
			(island_removal_mode 0)
		)
		(polygon
			(pts
				(xy 59.822842 -207.316578) (xy 59.822842 -206.87284) (xy 62.147958 -206.87284) (xy 62.147958 -207.316578)
			)
		)
	)
	(zone
		(layer "F.Cu")
		(hatch none 0.5)
		(connect_pads
			(clearance 0)
		)
		(min_thickness 0.25)
		(keepout
			(tracks not_allowed)
			(vias allowed)
			(pads allowed)
			(copperpour not_allowed)
			(footprints allowed)
		)
		(placement
			(enabled no)
			(sheetname "")
		)
		(fill
			(thermal_gap 0.5)
			(thermal_bridge_width 0.5)
			(island_removal_mode 0)
		)
		(polygon
			(pts
				(xy 65.469008 -11.992356) (xy 65.644268 -11.992356) (xy 65.672208 -11.964416) (xy 65.672208 -10.569956)
				(xy 65.649348 -10.547096) (xy 65.479168 -10.547096) (xy 65.458848 -10.567416) (xy 65.458848 -11.982196)
			)
		)
	)
	(zone
		(layer "F.Cu")
		(hatch none 0.5)
		(connect_pads
			(clearance 0)
		)
		(min_thickness 0.25)
		(keepout
			(tracks allowed)
			(vias allowed)
			(pads allowed)
			(copperpour allowed)
			(footprints not_allowed)
		)
		(placement
			(enabled no)
			(sheetname "")
		)
		(fill
			(thermal_gap 0.5)
			(thermal_bridge_width 0.5)
			(island_removal_mode 0)
		)
		(polygon
			(pts
				(xy 2.999994 -398.75587) (xy 34.536634 -398.75587) (xy 34.536634 -403.770084) (xy 48.200056 -403.770084)
				(xy 48.200056 -409.88996) (xy 54.200044 -409.88996) (xy 54.200044 -410.69006) (xy 167.340026 -410.69006)
				(xy 167.340026 -433.07)
				(arc
					(start 172.160692 -433.07)
					(mid 179.750172 -427.599957)
					(end 187.339478 -433.07)
				)
				(xy 190.33998 -433.07) (xy 190.33998 -403.770084) (xy 189.33922 -403.770084) (xy 189.33922 -398.75587)
				(xy 221.939866 -398.75587) (xy 221.939358 -374.753886) (xy 201.33945 -374.753886) (xy 201.33945 -355.763576)
				(xy 142.54861 -355.763576) (xy 142.54861 -363.21492) (xy 130.48107 -363.21492) (xy 130.48107 -355.763576)
				(xy 87.908638 -355.763576) (xy 87.908638 -363.21492) (xy 75.924918 -363.21492) (xy 75.924918 -355.763576)
				(xy 22.53996 -355.763576) (xy 22.53996 -374.753886) (xy 2.999994 -374.753886)
			)
		)
	)
	(zone
		(layer "F.Cu")
		(hatch none 0.5)
		(connect_pads
			(clearance 0)
		)
		(min_thickness 0.25)
		(keepout
			(tracks allowed)
			(vias allowed)
			(pads allowed)
			(copperpour allowed)
			(footprints allowed)
		)
		(placement
			(enabled no)
			(sheetname "")
		)
		(fill
			(thermal_gap 0.5)
			(thermal_bridge_width 0.5)
			(island_removal_mode 0)
		)
		(polygon
			(pts
				(xy 455.094594 -258.826254) (xy 457.126594 -258.826254) (xy 457.126594 -259.054854) (xy 455.094594 -259.054854)
				(xy 454.918826 -259.054854) (xy 454.918826 -258.826254)
			)
		)
	)
	(zone
		(layer "F.Cu")
		(hatch none 0.5)
		(connect_pads
			(clearance 0)
		)
		(min_thickness 0.25)
		(keepout
			(tracks allowed)
			(vias allowed)
			(pads allowed)
			(copperpour allowed)
			(footprints allowed)
		)
		(placement
			(enabled no)
			(sheetname "")
		)
		(fill
			(thermal_gap 0.5)
			(thermal_bridge_width 0.5)
			(island_removal_mode 0)
		)
		(polygon
			(pts
				(xy 277.58771 -268.516354) (xy 277.58771 -268.072616) (xy 277.58771 -267.659358) (xy 277.65121 -267.595858)
				(xy 279.946608 -267.595858) (xy 280.07945 -267.7287) (xy 280.07945 -268.467332) (xy 280.030428 -268.516354)
				(xy 279.912826 -268.516354)
			)
		)
	)
	(zone
		(layer "F.Cu")
		(hatch none 0.5)
		(connect_pads
			(clearance 0)
		)
		(min_thickness 0.25)
		(keepout
			(tracks allowed)
			(vias allowed)
			(pads allowed)
			(copperpour allowed)
			(footprints not_allowed)
		)
		(placement
			(enabled no)
			(sheetname "")
		)
		(fill
			(thermal_gap 0.5)
			(thermal_bridge_width 0.5)
			(island_removal_mode 0)
		)
		(polygon
			(pts
				(xy 282.502102 -79.76362) (xy 250.001024 -79.76362) (xy 250.001024 -82.763614) (xy 282.502102 -82.763614)
			)
		)
	)
	(zone
		(layer "F.Cu")
		(hatch none 0.5)
		(connect_pads
			(clearance 0)
		)
		(min_thickness 0.25)
		(keepout
			(tracks allowed)
			(vias allowed)
			(pads allowed)
			(copperpour allowed)
			(footprints allowed)
		)
		(placement
			(enabled no)
			(sheetname "")
		)
		(fill
			(thermal_gap 0.5)
			(thermal_bridge_width 0.5)
			(island_removal_mode 0)
		)
		(polygon
			(pts
				(xy 304.319178 -240.872772) (xy 306.644294 -240.872772) (xy 306.644294 -240.874042) (xy 306.72659 -240.874042)
				(xy 306.72659 -241.80419) (xy 304.185828 -241.80419) (xy 304.185828 -240.872772)
			)
		)
	)
	(zone
		(layer "F.Cu")
		(hatch none 0.5)
		(connect_pads
			(clearance 0)
		)
		(min_thickness 0.25)
		(keepout
			(tracks allowed)
			(vias allowed)
			(pads allowed)
			(copperpour allowed)
			(footprints allowed)
		)
		(placement
			(enabled no)
			(sheetname "")
		)
		(fill
			(thermal_gap 0.5)
			(thermal_bridge_width 0.5)
			(island_removal_mode 0)
		)
		(polygon
			(pts
				(xy 292.67531 -260.016498) (xy 292.67531 -259.57276) (xy 295.000426 -259.57276) (xy 295.000426 -260.016498)
			)
		)
	)
	(zone
		(layer "F.Cu")
		(hatch none 0.5)
		(connect_pads
			(clearance 0)
		)
		(min_thickness 0.25)
		(keepout
			(tracks not_allowed)
			(vias allowed)
			(pads allowed)
			(copperpour not_allowed)
			(footprints allowed)
		)
		(placement
			(enabled no)
			(sheetname "")
		)
		(fill
			(thermal_gap 0.5)
			(thermal_bridge_width 0.5)
			(island_removal_mode 0)
		)
		(polygon
			(pts
				(arc
					(start 137.029698 -206.024988)
					(mid 134.934706 -208.11998)
					(end 132.839714 -206.024988)
				)
				(arc
					(start 132.839714 -206.024988)
					(mid 134.934706 -203.929996)
					(end 137.029698 -206.024988)
				)
			)
		)
	)
	(zone
		(layer "F.Cu")
		(hatch none 0.5)
		(connect_pads
			(clearance 0)
		)
		(min_thickness 0.25)
		(keepout
			(tracks allowed)
			(vias allowed)
			(pads allowed)
			(copperpour allowed)
			(footprints allowed)
		)
		(placement
			(enabled no)
			(sheetname "")
		)
		(fill
			(thermal_gap 0.5)
			(thermal_bridge_width 0.5)
			(island_removal_mode 0)
		)
		(polygon
			(pts
				(xy 326.114156 -340.950296) (xy 326.114156 -344.955876) (xy 326.594216 -345.435936) (xy 328.659236 -345.435936)
				(xy 328.931016 -345.164156) (xy 328.931016 -343.309956) (xy 329.182476 -343.058496) (xy 331.102716 -343.058496)
				(xy 331.519276 -342.641936) (xy 331.519276 -341.150956) (xy 330.871576 -340.503256) (xy 326.561196 -340.503256)
			)
		)
	)
	(zone
		(layer "F.Cu")
		(hatch none 0.5)
		(connect_pads
			(clearance 0)
		)
		(min_thickness 0.25)
		(keepout
			(tracks allowed)
			(vias allowed)
			(pads allowed)
			(copperpour allowed)
			(footprints allowed)
		)
		(placement
			(enabled no)
			(sheetname "")
		)
		(fill
			(thermal_gap 0.5)
			(thermal_bridge_width 0.5)
			(island_removal_mode 0)
		)
		(polygon
			(pts
				(xy 41.29151 -207.316578) (xy 41.29151 -206.87284) (xy 43.616626 -206.87284) (xy 43.616626 -207.316578)
			)
		)
	)
	(zone
		(layer "F.Cu")
		(hatch none 0.5)
		(connect_pads
			(clearance 0)
		)
		(min_thickness 0.25)
		(keepout
			(tracks allowed)
			(vias allowed)
			(pads allowed)
			(copperpour allowed)
			(footprints allowed)
		)
		(placement
			(enabled no)
			(sheetname "")
		)
		(fill
			(thermal_gap 0.5)
			(thermal_bridge_width 0.5)
			(island_removal_mode 0)
		)
		(polygon
			(pts
				(xy 458.538326 -226.754944) (xy 458.538326 -226.526344) (xy 460.570326 -226.526344) (xy 460.570326 -226.754944)
			)
		)
	)
	(zone
		(layer "F.Cu")
		(hatch none 0.5)
		(connect_pads
			(clearance 0)
		)
		(min_thickness 0.25)
		(keepout
			(tracks allowed)
			(vias allowed)
			(pads allowed)
			(copperpour allowed)
			(footprints not_allowed)
		)
		(placement
			(enabled no)
			(sheetname "")
		)
		(fill
			(thermal_gap 0.5)
			(thermal_bridge_width 0.5)
			(island_removal_mode 0)
		)
		(polygon
			(pts
				(arc
					(start 330.900024 -160.50006)
					(mid 322.90004 -168.500044)
					(end 314.900056 -160.50006)
				)
				(arc
					(start 314.900056 -160.50006)
					(mid 322.90004 -152.500076)
					(end 330.900024 -160.50006)
				)
			)
		)
	)
	(zone
		(layer "F.Cu")
		(hatch none 0.5)
		(connect_pads
			(clearance 0)
		)
		(min_thickness 0.25)
		(keepout
			(tracks allowed)
			(vias allowed)
			(pads allowed)
			(copperpour allowed)
			(footprints allowed)
		)
		(placement
			(enabled no)
			(sheetname "")
		)
		(fill
			(thermal_gap 0.5)
			(thermal_bridge_width 0.5)
			(island_removal_mode 0)
		)
		(polygon
			(pts
				(xy 157.791658 -275.826474) (xy 159.823658 -275.826474) (xy 159.823658 -275.82876) (xy 160.002474 -275.82876)
				(xy 160.002474 -276.065996) (xy 160.140396 -276.065996) (xy 160.183576 -276.109176) (xy 160.183576 -276.242018)
				(xy 160.183576 -276.546056) (xy 160.110932 -276.6187) (xy 157.570678 -276.6187) (xy 157.429454 -276.477476)
				(xy 157.429454 -276.280372) (xy 157.510988 -276.198838) (xy 157.510988 -275.826474) (xy 157.608524 -275.826474)
				(xy 157.655514 -275.826474)
			)
		)
	)
	(zone
		(layer "F.Cu")
		(hatch none 0.5)
		(connect_pads
			(clearance 0)
		)
		(min_thickness 0.25)
		(keepout
			(tracks allowed)
			(vias allowed)
			(pads allowed)
			(copperpour allowed)
			(footprints allowed)
		)
		(placement
			(enabled no)
			(sheetname "")
		)
		(fill
			(thermal_gap 0.5)
			(thermal_bridge_width 0.5)
			(island_removal_mode 0)
		)
		(polygon
			(pts
				(xy 37.68598 -9.134348) (xy 37.68598 -6.218428) (xy 46.0629 -6.218428) (xy 46.0629 -9.134348)
			)
		)
	)
	(zone
		(layer "F.Cu")
		(hatch none 0.5)
		(connect_pads
			(clearance 0)
		)
		(min_thickness 0.25)
		(keepout
			(tracks allowed)
			(vias allowed)
			(pads allowed)
			(copperpour allowed)
			(footprints allowed)
		)
		(placement
			(enabled no)
			(sheetname "")
		)
		(fill
			(thermal_gap 0.5)
			(thermal_bridge_width 0.5)
			(island_removal_mode 0)
		)
		(polygon
			(pts
				(xy 443.450726 -262.454898) (xy 443.450726 -262.226298) (xy 445.482726 -262.226298) (xy 445.482726 -262.454898)
			)
		)
	)
	(zone
		(layer "F.Cu")
		(hatch none 0.5)
		(connect_pads
			(clearance 0)
		)
		(min_thickness 0.25)
		(keepout
			(tracks allowed)
			(vias allowed)
			(pads allowed)
			(copperpour allowed)
			(footprints allowed)
		)
		(placement
			(enabled no)
			(sheetname "")
		)
		(fill
			(thermal_gap 0.5)
			(thermal_bridge_width 0.5)
			(island_removal_mode 0)
		)
		(polygon
			(pts
				(xy 207.154526 -237.806992) (xy 209.186526 -237.806992) (xy 209.186526 -237.578392) (xy 207.154526 -237.578392)
				(xy 207.023208 -237.578392) (xy 206.9973 -237.578392) (xy 206.9973 -237.806992) (xy 207.023208 -237.806992)
			)
		)
	)
	(zone
		(layer "F.Cu")
		(hatch none 0.5)
		(connect_pads
			(clearance 0)
		)
		(min_thickness 0.25)
		(keepout
			(tracks allowed)
			(vias allowed)
			(pads allowed)
			(copperpour allowed)
			(footprints allowed)
		)
		(placement
			(enabled no)
			(sheetname "")
		)
		(fill
			(thermal_gap 0.5)
			(thermal_bridge_width 0.5)
			(island_removal_mode 0)
		)
		(polygon
			(pts
				(xy 443.450726 -216.554812) (xy 443.450726 -216.326212) (xy 445.482726 -216.326212) (xy 445.482726 -216.554812)
			)
		)
	)
	(zone
		(layer "F.Cu")
		(hatch none 0.5)
		(connect_pads
			(clearance 0)
		)
		(min_thickness 0.25)
		(keepout
			(tracks allowed)
			(vias allowed)
			(pads allowed)
			(copperpour allowed)
			(footprints allowed)
		)
		(placement
			(enabled no)
			(sheetname "")
		)
		(fill
			(thermal_gap 0.5)
			(thermal_bridge_width 0.5)
			(island_removal_mode 0)
		)
		(polygon
			(pts
				(xy 342.4047 -331.689456) (xy 342.4047 -335.695036) (xy 342.88476 -336.175096) (xy 344.94978 -336.175096)
				(xy 345.22156 -335.903316) (xy 345.22156 -334.049116) (xy 345.47302 -333.797656) (xy 347.39326 -333.797656)
				(xy 347.80982 -333.381096) (xy 347.80982 -331.890116) (xy 347.16212 -331.242416) (xy 342.85174 -331.242416)
			)
		)
	)
	(zone
		(layer "F.Cu")
		(hatch none 0.5)
		(connect_pads
			(clearance 0)
		)
		(min_thickness 0.25)
		(keepout
			(tracks allowed)
			(vias allowed)
			(pads allowed)
			(copperpour allowed)
			(footprints allowed)
		)
		(placement
			(enabled no)
			(sheetname "")
		)
		(fill
			(thermal_gap 0.5)
			(thermal_bridge_width 0.5)
			(island_removal_mode 0)
		)
		(polygon
			(pts
				(xy 63.951612 -239.17275) (xy 66.212212 -239.17275) (xy 66.308224 -239.17275) (xy 66.308224 -240.088674)
				(xy 63.807594 -240.088674) (xy 63.807594 -239.17275)
			)
		)
	)
	(zone
		(layer "F.Cu")
		(hatch none 0.5)
		(connect_pads
			(clearance 0)
		)
		(min_thickness 0.25)
		(keepout
			(tracks allowed)
			(vias allowed)
			(pads allowed)
			(copperpour allowed)
			(footprints allowed)
		)
		(placement
			(enabled no)
			(sheetname "")
		)
		(fill
			(thermal_gap 0.5)
			(thermal_bridge_width 0.5)
			(island_removal_mode 0)
		)
		(polygon
			(pts
				(xy 304.319178 -230.266494) (xy 304.319178 -229.822756) (xy 306.644294 -229.822756) (xy 306.644294 -230.266494)
			)
		)
	)
	(zone
		(layer "F.Cu")
		(hatch none 0.5)
		(connect_pads
			(clearance 0)
		)
		(min_thickness 0.25)
		(keepout
			(tracks allowed)
			(vias allowed)
			(pads allowed)
			(copperpour allowed)
			(footprints allowed)
		)
		(placement
			(enabled no)
			(sheetname "")
		)
		(fill
			(thermal_gap 0.5)
			(thermal_bridge_width 0.5)
			(island_removal_mode 0)
		)
		(polygon
			(pts
				(xy 409.831794 -207.204818) (xy 409.831794 -206.976218) (xy 411.863794 -206.976218) (xy 411.863794 -207.204818)
			)
		)
	)
	(zone
		(layer "F.Cu")
		(hatch none 0.5)
		(connect_pads
			(clearance 0)
		)
		(min_thickness 0.25)
		(keepout
			(tracks allowed)
			(vias allowed)
			(pads allowed)
			(copperpour allowed)
			(footprints allowed)
		)
		(placement
			(enabled no)
			(sheetname "")
		)
		(fill
			(thermal_gap 0.5)
			(thermal_bridge_width 0.5)
			(island_removal_mode 0)
		)
		(polygon
			(pts
				(xy 262.50011 -301.666656) (xy 262.50011 -301.222918) (xy 264.825226 -301.222918) (xy 264.825226 -301.666656)
			)
		)
	)
	(zone
		(layer "F.Cu")
		(hatch none 0.5)
		(connect_pads
			(clearance 0)
		)
		(min_thickness 0.25)
		(keepout
			(tracks allowed)
			(vias allowed)
			(pads allowed)
			(copperpour allowed)
			(footprints allowed)
		)
		(placement
			(enabled no)
			(sheetname "")
		)
		(fill
			(thermal_gap 0.5)
			(thermal_bridge_width 0.5)
			(island_removal_mode 0)
		)
		(polygon
			(pts
				(xy 176.979326 -216.326466) (xy 179.011326 -216.326466) (xy 179.011326 -216.555066) (xy 176.979326 -216.555066)
				(xy 176.843182 -216.555066) (xy 176.796192 -216.555066) (xy 176.796192 -216.326466) (xy 176.843182 -216.326466)
			)
		)
	)
	(zone
		(layer "F.Cu")
		(hatch none 0.5)
		(connect_pads
			(clearance 0)
		)
		(min_thickness 0.25)
		(keepout
			(tracks allowed)
			(vias allowed)
			(pads allowed)
			(copperpour allowed)
			(footprints allowed)
		)
		(placement
			(enabled no)
			(sheetname "")
		)
		(fill
			(thermal_gap 0.5)
			(thermal_bridge_width 0.5)
			(island_removal_mode 0)
		)
		(polygon
			(pts
				(xy 195.510658 -310.055006) (xy 195.510658 -309.826406) (xy 197.542658 -309.826406) (xy 197.542658 -310.055006)
			)
		)
	)
	(zone
		(layer "F.Cu")
		(hatch none 0.5)
		(connect_pads
			(clearance 0)
		)
		(min_thickness 0.25)
		(keepout
			(tracks allowed)
			(vias allowed)
			(pads allowed)
			(copperpour allowed)
			(footprints allowed)
		)
		(placement
			(enabled no)
			(sheetname "")
		)
		(fill
			(thermal_gap 0.5)
			(thermal_bridge_width 0.5)
			(island_removal_mode 0)
		)
		(polygon
			(pts
				(xy 26.20391 -234.922822) (xy 28.529026 -234.922822) (xy 28.598622 -234.922822) (xy 28.598622 -235.848906)
				(xy 26.069798 -235.848906) (xy 26.069798 -234.922822)
			)
		)
	)
	(zone
		(layer "F.Cu")
		(hatch none 0.5)
		(connect_pads
			(clearance 0)
		)
		(min_thickness 0.25)
		(keepout
			(tracks allowed)
			(vias allowed)
			(pads allowed)
			(copperpour allowed)
			(footprints allowed)
		)
		(placement
			(enabled no)
			(sheetname "")
		)
		(fill
			(thermal_gap 0.5)
			(thermal_bridge_width 0.5)
			(island_removal_mode 0)
		)
		(polygon
			(pts
				(xy 307.76291 -247.26646) (xy 307.76291 -246.822722) (xy 310.088026 -246.822722) (xy 310.088026 -247.26646)
			)
		)
	)
	(zone
		(layer "F.Cu")
		(hatch none 0.5)
		(connect_pads
			(clearance 0)
		)
		(min_thickness 0.25)
		(keepout
			(tracks allowed)
			(vias allowed)
			(pads allowed)
			(copperpour allowed)
			(footprints not_allowed)
		)
		(placement
			(enabled no)
			(sheetname "")
		)
		(fill
			(thermal_gap 0.5)
			(thermal_bridge_width 0.5)
			(island_removal_mode 0)
		)
		(polygon
			(pts
				(arc
					(start 5.340096 -347.700092)
					(mid 10.340086 -342.700102)
					(end 15.340076 -347.700092)
				)
				(arc
					(start 15.340076 -347.700092)
					(mid 10.340086 -352.700082)
					(end 5.340096 -347.700092)
				)
			)
		)
	)
	(zone
		(layer "F.Cu")
		(hatch none 0.5)
		(connect_pads
			(clearance 0)
		)
		(min_thickness 0.25)
		(keepout
			(tracks allowed)
			(vias allowed)
			(pads allowed)
			(copperpour allowed)
			(footprints allowed)
		)
		(placement
			(enabled no)
			(sheetname "")
		)
		(fill
			(thermal_gap 0.5)
			(thermal_bridge_width 0.5)
			(island_removal_mode 0)
		)
		(polygon
			(pts
				(xy 133.6929 -289.029648) (xy 133.97992 -289.029648) (xy 134.0104 -288.999168) (xy 134.0104 -288.371788)
				(xy 133.92404 -288.285428) (xy 133.73608 -288.285428) (xy 133.66242 -288.359088) (xy 133.66242 -288.999168)
			)
		)
	)
	(zone
		(layer "F.Cu")
		(hatch none 0.5)
		(connect_pads
			(clearance 0)
		)
		(min_thickness 0.25)
		(keepout
			(tracks allowed)
			(vias allowed)
			(pads allowed)
			(copperpour allowed)
			(footprints not_allowed)
		)
		(placement
			(enabled no)
			(sheetname "")
		)
		(fill
			(thermal_gap 0.5)
			(thermal_bridge_width 0.5)
			(island_removal_mode 0)
		)
		(polygon
			(pts
				(xy 282.501848 -87.29091) (xy 303.502568 -87.293196) (xy 303.502568 -59.993276) (xy 282.504642 -59.99099)
			)
		)
	)
	(zone
		(layer "F.Cu")
		(hatch none 0.5)
		(connect_pads
			(clearance 0)
		)
		(min_thickness 0.25)
		(keepout
			(tracks allowed)
			(vias allowed)
			(pads allowed)
			(copperpour allowed)
			(footprints allowed)
		)
		(placement
			(enabled no)
			(sheetname "")
		)
		(fill
			(thermal_gap 0.5)
			(thermal_bridge_width 0.5)
			(island_removal_mode 0)
		)
		(polygon
			(pts
				(xy 259.056378 -205.616556) (xy 259.056378 -205.172818) (xy 261.381494 -205.172818) (xy 261.381494 -205.616556)
			)
		)
	)
	(zone
		(layer "F.Cu")
		(hatch none 0.5)
		(connect_pads
			(clearance 0)
		)
		(min_thickness 0.25)
		(keepout
			(tracks allowed)
			(vias allowed)
			(pads allowed)
			(copperpour allowed)
			(footprints allowed)
		)
		(placement
			(enabled no)
			(sheetname "")
		)
		(fill
			(thermal_gap 0.5)
			(thermal_bridge_width 0.5)
			(island_removal_mode 0)
		)
		(polygon
			(pts
				(xy 14.560042 -269.366492) (xy 14.560042 -268.922754) (xy 16.885158 -268.922754) (xy 16.885158 -269.366492)
			)
		)
	)
	(zone
		(layer "F.Cu")
		(hatch none 0.5)
		(connect_pads
			(clearance 0)
		)
		(min_thickness 0.25)
		(keepout
			(tracks allowed)
			(vias allowed)
			(pads allowed)
			(copperpour allowed)
			(footprints allowed)
		)
		(placement
			(enabled no)
			(sheetname "")
		)
		(fill
			(thermal_gap 0.5)
			(thermal_bridge_width 0.5)
			(island_removal_mode 0)
		)
		(polygon
			(pts
				(xy 458.538326 -308.354984) (xy 458.538326 -308.126384) (xy 460.570326 -308.126384) (xy 460.570326 -308.354984)
			)
		)
	)
	(zone
		(layer "F.Cu")
		(hatch none 0.5)
		(connect_pads
			(clearance 0)
		)
		(min_thickness 0.25)
		(keepout
			(tracks allowed)
			(vias allowed)
			(pads allowed)
			(copperpour allowed)
			(footprints allowed)
		)
		(placement
			(enabled no)
			(sheetname "")
		)
		(fill
			(thermal_gap 0.5)
			(thermal_bridge_width 0.5)
			(island_removal_mode 0)
		)
		(polygon
			(pts
				(xy 29.647642 -277.422864) (xy 31.972758 -277.422864) (xy 32.04464 -277.422864) (xy 32.04464 -278.338788)
				(xy 29.51607 -278.338788) (xy 29.51607 -277.422864)
			)
		)
	)
	(zone
		(layer "F.Cu")
		(hatch none 0.5)
		(connect_pads
			(clearance 0)
		)
		(min_thickness 0.25)
		(keepout
			(tracks not_allowed)
			(vias allowed)
			(pads allowed)
			(copperpour not_allowed)
			(footprints allowed)
		)
		(placement
			(enabled no)
			(sheetname "")
		)
		(fill
			(thermal_gap 0.5)
			(thermal_bridge_width 0.5)
			(island_removal_mode 0)
		)
		(polygon
			(pts
				(xy 39.520622 -356.092252) (xy 43.4467 -356.092252) (xy 43.4467 -356.02926) (xy 43.32478 -355.90734)
				(xy 41.908476 -355.90734) (xy 41.908476 -353.74834) (xy 44.06519 -353.74834) (xy 44.06519 -353.498658)
				(xy 41.72966 -353.498658) (xy 41.72966 -353.822508) (xy 41.617138 -353.822508) (xy 41.617138 -355.851714)
				(xy 39.762938 -355.851714) (xy 39.762938 -355.610668) (xy 39.520622 -355.610668)
			)
		)
	)
	(zone
		(layer "F.Cu")
		(hatch none 0.5)
		(connect_pads
			(clearance 0)
		)
		(min_thickness 0.25)
		(keepout
			(tracks allowed)
			(vias allowed)
			(pads allowed)
			(copperpour allowed)
			(footprints allowed)
		)
		(placement
			(enabled no)
			(sheetname "")
		)
		(fill
			(thermal_gap 0.5)
			(thermal_bridge_width 0.5)
			(island_removal_mode 0)
		)
		(polygon
			(pts
				(xy 63.977012 -260.866636) (xy 63.977012 -260.422898) (xy 66.186812 -260.422898) (xy 66.186812 -260.866636)
			)
		)
	)
	(zone
		(layer "F.Cu")
		(hatch none 0.5)
		(connect_pads
			(clearance 0)
		)
		(min_thickness 0.25)
		(keepout
			(tracks allowed)
			(vias allowed)
			(pads allowed)
			(copperpour allowed)
			(footprints allowed)
		)
		(placement
			(enabled no)
			(sheetname "")
		)
		(fill
			(thermal_gap 0.5)
			(thermal_bridge_width 0.5)
			(island_removal_mode 0)
		)
		(polygon
			(pts
				(xy 176.979326 -276.676358) (xy 179.011326 -276.676358) (xy 179.011326 -276.904958) (xy 176.979326 -276.904958)
				(xy 176.843182 -276.904958) (xy 176.796192 -276.904958) (xy 176.796192 -276.676358) (xy 176.843182 -276.676358)
			)
		)
	)
	(zone
		(layer "F.Cu")
		(hatch none 0.5)
		(connect_pads
			(clearance 0)
		)
		(min_thickness 0.25)
		(keepout
			(tracks allowed)
			(vias allowed)
			(pads allowed)
			(copperpour allowed)
			(footprints allowed)
		)
		(placement
			(enabled no)
			(sheetname "")
		)
		(fill
			(thermal_gap 0.5)
			(thermal_bridge_width 0.5)
			(island_removal_mode 0)
		)
		(polygon
			(pts
				(xy 41.29151 -222.616522) (xy 41.29151 -222.172784) (xy 43.616626 -222.172784) (xy 43.616626 -222.616522)
			)
		)
	)
	(zone
		(layer "F.Cu")
		(hatch none 0.5)
		(connect_pads
			(clearance 0)
		)
		(min_thickness 0.25)
		(keepout
			(tracks not_allowed)
			(vias allowed)
			(pads allowed)
			(copperpour not_allowed)
			(footprints allowed)
		)
		(placement
			(enabled no)
			(sheetname "")
		)
		(fill
			(thermal_gap 0.5)
			(thermal_bridge_width 0.5)
			(island_removal_mode 0)
		)
		(polygon
			(pts
				(arc
					(start 290.74999 -435.600094)
					(mid 293.550086 -432.799998)
					(end 296.349928 -435.600094)
				)
				(arc
					(start 296.349928 -435.600094)
					(mid 293.550086 -438.399936)
					(end 290.74999 -435.600094)
				)
			)
		)
	)
	(zone
		(layer "F.Cu")
		(hatch none 0.5)
		(connect_pads
			(clearance 0)
		)
		(min_thickness 0.25)
		(keepout
			(tracks allowed)
			(vias allowed)
			(pads allowed)
			(copperpour allowed)
			(footprints allowed)
		)
		(placement
			(enabled no)
			(sheetname "")
		)
		(fill
			(thermal_gap 0.5)
			(thermal_bridge_width 0.5)
			(island_removal_mode 0)
		)
		(polygon
			(pts
				(xy 63.926212 -242.968272) (xy 66.237612 -242.968272) (xy 66.237612 -243.857272) (xy 63.926212 -243.857272)
				(xy 63.811912 -243.857272) (xy 63.811912 -242.968272)
			)
		)
	)
	(zone
		(layer "F.Cu")
		(hatch none 0.5)
		(connect_pads
			(clearance 0)
		)
		(min_thickness 0.25)
		(keepout
			(tracks allowed)
			(vias allowed)
			(pads allowed)
			(copperpour allowed)
			(footprints not_allowed)
		)
		(placement
			(enabled no)
			(sheetname "")
		)
		(fill
			(thermal_gap 0.5)
			(thermal_bridge_width 0.5)
			(island_removal_mode 0)
		)
		(polygon
			(pts
				(xy 292.79977 -330.091796) (xy 298.89958 -330.091796) (xy 298.89958 -186.09183) (xy 292.79977 -186.09183)
			)
		)
	)
	(zone
		(layer "F.Cu")
		(hatch none 0.5)
		(connect_pads
			(clearance 0)
		)
		(min_thickness 0.25)
		(keepout
			(tracks allowed)
			(vias allowed)
			(pads allowed)
			(copperpour allowed)
			(footprints allowed)
		)
		(placement
			(enabled no)
			(sheetname "")
		)
		(fill
			(thermal_gap 0.5)
			(thermal_bridge_width 0.5)
			(island_removal_mode 0)
		)
		(polygon
			(pts
				(xy 129.28346 -14.305788) (xy 129.28346 -11.925808) (xy 137.414 -11.925808) (xy 137.414 -14.305788)
			)
		)
	)
	(zone
		(layer "F.Cu")
		(hatch none 0.5)
		(connect_pads
			(clearance 0)
		)
		(min_thickness 0.25)
		(keepout
			(tracks allowed)
			(vias allowed)
			(pads allowed)
			(copperpour allowed)
			(footprints allowed)
		)
		(placement
			(enabled no)
			(sheetname "")
		)
		(fill
			(thermal_gap 0.5)
			(thermal_bridge_width 0.5)
			(island_removal_mode 0)
		)
		(polygon
			(pts
				(xy 424.919394 -300.476412) (xy 426.951394 -300.476412) (xy 426.951394 -300.705012) (xy 424.919394 -300.705012)
				(xy 424.78325 -300.705012) (xy 424.73626 -300.705012) (xy 424.73626 -300.476412) (xy 424.78325 -300.476412)
			)
		)
	)
	(zone
		(layer "F.Cu")
		(hatch none 0.5)
		(connect_pads
			(clearance 0)
		)
		(min_thickness 0.25)
		(keepout
			(tracks allowed)
			(vias allowed)
			(pads allowed)
			(copperpour allowed)
			(footprints allowed)
		)
		(placement
			(enabled no)
			(sheetname "")
		)
		(fill
			(thermal_gap 0.5)
			(thermal_bridge_width 0.5)
			(island_removal_mode 0)
		)
		(polygon
			(pts
				(xy 311.94248 -313.566556) (xy 311.94248 -313.122818) (xy 314.10148 -313.122818) (xy 314.10148 -313.566556)
			)
		)
	)
	(zone
		(layer "F.Cu")
		(hatch none 0.5)
		(connect_pads
			(clearance 0)
		)
		(min_thickness 0.25)
		(keepout
			(tracks allowed)
			(vias allowed)
			(pads allowed)
			(copperpour allowed)
			(footprints not_allowed)
		)
		(placement
			(enabled no)
			(sheetname "")
		)
		(fill
			(thermal_gap 0.5)
			(thermal_bridge_width 0.5)
			(island_removal_mode 0)
		)
		(polygon
			(pts
				(xy 404.753572 -185.091832) (xy 404.753572 -331.091794) (xy 465.659978 -331.091794) (xy 465.659978 -185.091832)
			)
		)
	)
	(zone
		(layer "F.Cu")
		(hatch none 0.5)
		(connect_pads
			(clearance 0)
		)
		(min_thickness 0.25)
		(keepout
			(tracks allowed)
			(vias allowed)
			(pads allowed)
			(copperpour allowed)
			(footprints allowed)
		)
		(placement
			(enabled no)
			(sheetname "")
		)
		(fill
			(thermal_gap 0.5)
			(thermal_bridge_width 0.5)
			(island_removal_mode 0)
		)
		(polygon
			(pts
				(xy 11.11631 -277.016464) (xy 11.11631 -276.572726) (xy 13.441426 -276.572726) (xy 13.441426 -277.016464)
			)
		)
	)
	(zone
		(layer "F.Cu")
		(hatch none 0.5)
		(connect_pads
			(clearance 0)
		)
		(min_thickness 0.25)
		(keepout
			(tracks allowed)
			(vias allowed)
			(pads allowed)
			(copperpour allowed)
			(footprints allowed)
		)
		(placement
			(enabled no)
			(sheetname "")
		)
		(fill
			(thermal_gap 0.5)
			(thermal_bridge_width 0.5)
			(island_removal_mode 0)
		)
		(polygon
			(pts
				(xy 360.37393 -332.908402) (xy 358.55783 -332.908402) (xy 358.55783 -331.529182) (xy 360.37393 -331.529182)
			)
		)
	)
	(zone
		(layer "F.Cu")
		(hatch none 0.5)
		(connect_pads
			(clearance 0)
		)
		(min_thickness 0.25)
		(keepout
			(tracks allowed)
			(vias allowed)
			(pads allowed)
			(copperpour allowed)
			(footprints not_allowed)
		)
		(placement
			(enabled no)
			(sheetname "")
		)
		(fill
			(thermal_gap 0.5)
			(thermal_bridge_width 0.5)
			(island_removal_mode 0)
		)
		(polygon
			(pts
				(xy 151.9301 -311.770014) (xy 151.9301 -191.77) (xy 71.930006 -191.77) (xy 71.930006 -311.770014)
				(xy 111.879888 -311.770014) (xy 111.879888 -296.720006) (xy 102.225094 -296.720006) (xy 102.225094 -293.269924)
				(xy 121.635012 -293.269924) (xy 121.635012 -296.720006) (xy 111.979964 -296.720006) (xy 111.979964 -311.770014)
			)
		)
	)
	(zone
		(layer "F.Cu")
		(hatch none 0.5)
		(connect_pads
			(clearance 0)
		)
		(min_thickness 0.25)
		(keepout
			(tracks allowed)
			(vias allowed)
			(pads allowed)
			(copperpour allowed)
			(footprints allowed)
		)
		(placement
			(enabled no)
			(sheetname "")
		)
		(fill
			(thermal_gap 0.5)
			(thermal_bridge_width 0.5)
			(island_removal_mode 0)
		)
		(polygon
			(pts
				(xy 259.056378 -305.066446) (xy 259.056378 -304.622708) (xy 261.381494 -304.622708) (xy 261.381494 -305.066446)
			)
		)
	)
	(zone
		(layer "F.Cu")
		(hatch none 0.5)
		(connect_pads
			(clearance 0)
		)
		(min_thickness 0.25)
		(keepout
			(tracks allowed)
			(vias allowed)
			(pads allowed)
			(copperpour allowed)
			(footprints allowed)
		)
		(placement
			(enabled no)
			(sheetname "")
		)
		(fill
			(thermal_gap 0.5)
			(thermal_bridge_width 0.5)
			(island_removal_mode 0)
		)
		(polygon
			(pts
				(xy 307.76291 -218.366594) (xy 307.76291 -217.922856) (xy 310.088026 -217.922856) (xy 310.088026 -218.366594)
			)
		)
	)
	(zone
		(layer "F.Cu")
		(hatch none 0.5)
		(connect_pads
			(clearance 0)
		)
		(min_thickness 0.25)
		(keepout
			(tracks allowed)
			(vias allowed)
			(pads allowed)
			(copperpour allowed)
			(footprints allowed)
		)
		(placement
			(enabled no)
			(sheetname "")
		)
		(fill
			(thermal_gap 0.5)
			(thermal_bridge_width 0.5)
			(island_removal_mode 0)
		)
		(polygon
			(pts
				(xy 41.29151 -235.36656) (xy 41.29151 -234.922822) (xy 43.616626 -234.922822) (xy 43.616626 -235.36656)
			)
		)
	)
	(zone
		(layer "F.Cu")
		(hatch none 0.5)
		(connect_pads
			(clearance 0)
		)
		(min_thickness 0.25)
		(keepout
			(tracks allowed)
			(vias allowed)
			(pads allowed)
			(copperpour allowed)
			(footprints allowed)
		)
		(placement
			(enabled no)
			(sheetname "")
		)
		(fill
			(thermal_gap 0.5)
			(thermal_bridge_width 0.5)
			(island_removal_mode 0)
		)
		(polygon
			(pts
				(xy 207.154526 -297.076368) (xy 209.186526 -297.076368) (xy 209.186526 -297.304968) (xy 207.154526 -297.304968)
				(xy 207.018382 -297.304968) (xy 206.971392 -297.304968) (xy 206.971392 -297.076368) (xy 207.018382 -297.076368)
			)
		)
	)
	(zone
		(layer "F.Cu")
		(hatch none 0.5)
		(connect_pads
			(clearance 0)
		)
		(min_thickness 0.25)
		(keepout
			(tracks allowed)
			(vias allowed)
			(pads allowed)
			(copperpour allowed)
			(footprints allowed)
		)
		(placement
			(enabled no)
			(sheetname "")
		)
		(fill
			(thermal_gap 0.5)
			(thermal_bridge_width 0.5)
			(island_removal_mode 0)
		)
		(polygon
			(pts
				(xy 424.919394 -246.304816) (xy 424.919394 -246.076216) (xy 426.951394 -246.076216) (xy 426.951394 -246.304816)
			)
		)
	)
	(zone
		(layer "F.Cu")
		(hatch none 0.5)
		(connect_pads
			(clearance 0)
		)
		(min_thickness 0.25)
		(keepout
			(tracks allowed)
			(vias allowed)
			(pads allowed)
			(copperpour allowed)
			(footprints not_allowed)
		)
		(placement
			(enabled no)
			(sheetname "")
		)
		(fill
			(thermal_gap 0.5)
			(thermal_bridge_width 0.5)
			(island_removal_mode 0)
		)
		(polygon
			(pts
				(xy 255.080008 -339.092032) (xy 313.986926 -339.092032) (xy 313.986926 -331.092048) (xy 255.080008 -331.092048)
			)
		)
	)
	(zone
		(layer "F.Cu")
		(hatch none 0.5)
		(connect_pads
			(clearance 0)
		)
		(min_thickness 0.25)
		(keepout
			(tracks allowed)
			(vias allowed)
			(pads allowed)
			(copperpour allowed)
			(footprints allowed)
		)
		(placement
			(enabled no)
			(sheetname "")
		)
		(fill
			(thermal_gap 0.5)
			(thermal_bridge_width 0.5)
			(island_removal_mode 0)
		)
		(polygon
			(pts
				(xy 443.450726 -207.204818) (xy 443.450726 -206.976218) (xy 445.482726 -206.976218) (xy 445.482726 -207.204818)
			)
		)
	)
	(zone
		(layer "F.Cu")
		(hatch none 0.5)
		(connect_pads
			(clearance 0)
		)
		(min_thickness 0.25)
		(keepout
			(tracks not_allowed)
			(vias allowed)
			(pads allowed)
			(copperpour not_allowed)
			(footprints allowed)
		)
		(placement
			(enabled no)
			(sheetname "")
		)
		(fill
			(thermal_gap 0.5)
			(thermal_bridge_width 0.5)
			(island_removal_mode 0)
		)
		(polygon
			(pts
				(arc
					(start 395.974824 -251.76988)
					(mid 393.879832 -253.864872)
					(end 391.78484 -251.76988)
				)
				(arc
					(start 391.78484 -251.76988)
					(mid 393.879832 -249.674888)
					(end 395.974824 -251.76988)
				)
			)
		)
	)
	(zone
		(layer "F.Cu")
		(hatch none 0.5)
		(connect_pads
			(clearance 0)
		)
		(min_thickness 0.25)
		(keepout
			(tracks allowed)
			(vias allowed)
			(pads allowed)
			(copperpour allowed)
			(footprints allowed)
		)
		(placement
			(enabled no)
			(sheetname "")
		)
		(fill
			(thermal_gap 0.5)
			(thermal_bridge_width 0.5)
			(island_removal_mode 0)
		)
		(polygon
			(pts
				(xy 311.91708 -265.966448) (xy 311.91708 -265.52271) (xy 314.15228 -265.52271) (xy 314.15228 -265.966448)
			)
		)
	)
	(zone
		(layer "F.Cu")
		(hatch none 0.5)
		(connect_pads
			(clearance 0)
		)
		(min_thickness 0.25)
		(keepout
			(tracks allowed)
			(vias allowed)
			(pads allowed)
			(copperpour allowed)
			(footprints not_allowed)
		)
		(placement
			(enabled no)
			(sheetname "")
		)
		(fill
			(thermal_gap 0.5)
			(thermal_bridge_width 0.5)
			(island_removal_mode 0)
		)
		(polygon
			(pts
				(xy 104.005126 -237.00994) (xy 104.005126 -261.62) (xy 107.63504 -261.62) (xy 107.63504 -237.00994)
			)
		)
	)
	(zone
		(layer "F.Cu")
		(hatch none 0.5)
		(connect_pads
			(clearance 0)
		)
		(min_thickness 0.25)
		(keepout
			(tracks allowed)
			(vias allowed)
			(pads allowed)
			(copperpour allowed)
			(footprints allowed)
		)
		(placement
			(enabled no)
			(sheetname "")
		)
		(fill
			(thermal_gap 0.5)
			(thermal_bridge_width 0.5)
			(island_removal_mode 0)
		)
		(polygon
			(pts
				(xy 210.598258 -289.654996) (xy 210.598258 -289.426396) (xy 212.630258 -289.426396) (xy 212.630258 -289.654996)
			)
		)
	)
	(zone
		(layer "F.Cu")
		(hatch none 0.5)
		(connect_pads
			(clearance 0)
		)
		(min_thickness 0.25)
		(keepout
			(tracks allowed)
			(vias allowed)
			(pads allowed)
			(copperpour allowed)
			(footprints allowed)
		)
		(placement
			(enabled no)
			(sheetname "")
		)
		(fill
			(thermal_gap 0.5)
			(thermal_bridge_width 0.5)
			(island_removal_mode 0)
		)
		(polygon
			(pts
				(xy 63.977012 -200.51649) (xy 63.977012 -200.072752) (xy 66.237612 -200.072752) (xy 66.237612 -200.51649)
			)
		)
	)
	(zone
		(layer "F.Cu")
		(hatch none 0.5)
		(connect_pads
			(clearance 0)
		)
		(min_thickness 0.25)
		(keepout
			(tracks allowed)
			(vias allowed)
			(pads allowed)
			(copperpour allowed)
			(footprints allowed)
		)
		(placement
			(enabled no)
			(sheetname "")
		)
		(fill
			(thermal_gap 0.5)
			(thermal_bridge_width 0.5)
			(island_removal_mode 0)
		)
		(polygon
			(pts
				(xy 176.29886 -56.418988) (xy 176.29886 -41.874948) (xy 179.1462 -41.874948) (xy 179.1462 -56.418988)
			)
		)
	)
	(zone
		(layer "F.Cu")
		(hatch none 0.5)
		(connect_pads
			(clearance 0)
		)
		(min_thickness 0.25)
		(keepout
			(tracks allowed)
			(vias allowed)
			(pads allowed)
			(copperpour allowed)
			(footprints allowed)
		)
		(placement
			(enabled no)
			(sheetname "")
		)
		(fill
			(thermal_gap 0.5)
			(thermal_bridge_width 0.5)
			(island_removal_mode 0)
		)
		(polygon
			(pts
				(xy 197.553834 -276.90699) (xy 195.521834 -276.90699) (xy 195.521834 -276.904704) (xy 195.343018 -276.904704)
				(xy 195.343018 -276.667468) (xy 195.205096 -276.667468) (xy 195.161916 -276.624288) (xy 195.161916 -276.491446)
				(xy 195.161916 -276.187408) (xy 195.23456 -276.114764) (xy 197.774814 -276.114764) (xy 197.916038 -276.255988)
				(xy 197.916038 -276.453092) (xy 197.834504 -276.534626) (xy 197.834504 -276.90699) (xy 197.736968 -276.90699)
				(xy 197.689978 -276.90699)
			)
		)
	)
	(zone
		(layer "F.Cu")
		(hatch none 0.5)
		(connect_pads
			(clearance 0)
		)
		(min_thickness 0.25)
		(keepout
			(tracks allowed)
			(vias allowed)
			(pads allowed)
			(copperpour allowed)
			(footprints not_allowed)
		)
		(placement
			(enabled no)
			(sheetname "")
		)
		(fill
			(thermal_gap 0.5)
			(thermal_bridge_width 0.5)
			(island_removal_mode 0)
		)
		(polygon
			(pts
				(arc
					(start 259.80009 -27.756866)
					(mid 264.695535 -30.242741)
					(end 270.040608 -28.987496)
				)
				(arc
					(start 270.040608 -24.692356)
					(mid 270.545894 -23.314911)
					(end 270.629634 -21.850096)
				)
				(arc
					(start 273.637248 -21.850096)
					(mid 268.372076 -14.777353)
					(end 259.80009 -16.842994)
				)
			)
		)
	)
	(zone
		(layer "F.Cu")
		(hatch none 0.5)
		(connect_pads
			(clearance 0)
		)
		(min_thickness 0.25)
		(keepout
			(tracks allowed)
			(vias allowed)
			(pads allowed)
			(copperpour allowed)
			(footprints allowed)
		)
		(placement
			(enabled no)
			(sheetname "")
		)
		(fill
			(thermal_gap 0.5)
			(thermal_bridge_width 0.5)
			(island_removal_mode 0)
		)
		(polygon
			(pts
				(xy 337.8327 -215.227408) (xy 338.11972 -215.227408) (xy 338.1502 -215.196928) (xy 338.1502 -214.569548)
				(xy 338.06384 -214.483188) (xy 337.87588 -214.483188) (xy 337.80222 -214.556848) (xy 337.80222 -215.196928)
			)
		)
	)
	(zone
		(layer "F.Cu")
		(hatch none 0.5)
		(connect_pads
			(clearance 0)
		)
		(min_thickness 0.25)
		(keepout
			(tracks allowed)
			(vias allowed)
			(pads allowed)
			(copperpour allowed)
			(footprints allowed)
		)
		(placement
			(enabled no)
			(sheetname "")
		)
		(fill
			(thermal_gap 0.5)
			(thermal_bridge_width 0.5)
			(island_removal_mode 0)
		)
		(polygon
			(pts
				(xy 304.319178 -294.01643) (xy 304.319178 -293.572692) (xy 306.644294 -293.572692) (xy 306.644294 -294.01643)
			)
		)
	)
	(zone
		(layer "F.Cu")
		(hatch none 0.5)
		(connect_pads
			(clearance 0)
		)
		(min_thickness 0.25)
		(keepout
			(tracks allowed)
			(vias allowed)
			(pads allowed)
			(copperpour allowed)
			(footprints allowed)
		)
		(placement
			(enabled no)
			(sheetname "")
		)
		(fill
			(thermal_gap 0.5)
			(thermal_bridge_width 0.5)
			(island_removal_mode 0)
		)
		(polygon
			(pts
				(xy 59.822842 -277.422864) (xy 62.147958 -277.422864) (xy 62.168786 -277.422864) (xy 62.168786 -278.406352)
				(xy 59.712606 -278.406352) (xy 59.712606 -277.422864)
			)
		)
	)
	(zone
		(layer "F.Cu")
		(hatch none 0.5)
		(connect_pads
			(clearance 0)
		)
		(min_thickness 0.25)
		(keepout
			(tracks allowed)
			(vias allowed)
			(pads allowed)
			(copperpour allowed)
			(footprints not_allowed)
		)
		(placement
			(enabled no)
			(sheetname "")
		)
		(fill
			(thermal_gap 0.5)
			(thermal_bridge_width 0.5)
			(island_removal_mode 0)
		)
		(polygon
			(pts
				(arc
					(start 176.950116 -435.600094)
					(mid 179.750212 -432.799998)
					(end 182.550054 -435.600094)
				)
				(arc
					(start 182.550054 -435.600094)
					(mid 179.750212 -438.399936)
					(end 176.950116 -435.600094)
				)
			)
		)
	)
	(zone
		(layer "F.Cu")
		(hatch none 0.5)
		(connect_pads
			(clearance 0)
		)
		(min_thickness 0.25)
		(keepout
			(tracks allowed)
			(vias allowed)
			(pads allowed)
			(copperpour allowed)
			(footprints allowed)
		)
		(placement
			(enabled no)
			(sheetname "")
		)
		(fill
			(thermal_gap 0.5)
			(thermal_bridge_width 0.5)
			(island_removal_mode 0)
		)
		(polygon
			(pts
				(xy 262.50011 -203.06665) (xy 262.50011 -202.622912) (xy 264.825226 -202.622912) (xy 264.825226 -203.06665)
			)
		)
	)
	(zone
		(layer "F.Cu")
		(hatch none 0.5)
		(connect_pads
			(clearance 0)
		)
		(min_thickness 0.25)
		(keepout
			(tracks allowed)
			(vias allowed)
			(pads allowed)
			(copperpour allowed)
			(footprints allowed)
		)
		(placement
			(enabled no)
			(sheetname "")
		)
		(fill
			(thermal_gap 0.5)
			(thermal_bridge_width 0.5)
			(island_removal_mode 0)
		)
		(polygon
			(pts
				(xy 262.50011 -286.366458) (xy 262.50011 -285.92272) (xy 264.825226 -285.92272) (xy 264.825226 -286.366458)
			)
		)
	)
	(zone
		(layer "F.Cu")
		(hatch none 0.5)
		(connect_pads
			(clearance 0)
		)
		(min_thickness 0.25)
		(keepout
			(tracks allowed)
			(vias allowed)
			(pads allowed)
			(copperpour allowed)
			(footprints allowed)
		)
		(placement
			(enabled no)
			(sheetname "")
		)
		(fill
			(thermal_gap 0.5)
			(thermal_bridge_width 0.5)
			(island_removal_mode 0)
		)
		(polygon
			(pts
				(xy 192.066926 -295.376346) (xy 194.098926 -295.376346) (xy 194.098926 -295.604946) (xy 192.066926 -295.604946)
				(xy 191.930782 -295.604946) (xy 191.883792 -295.604946) (xy 191.883792 -295.376346) (xy 191.930782 -295.376346)
			)
		)
	)
	(zone
		(layer "F.Cu")
		(hatch none 0.5)
		(connect_pads
			(clearance 0)
		)
		(min_thickness 0.25)
		(keepout
			(tracks allowed)
			(vias allowed)
			(pads allowed)
			(copperpour allowed)
			(footprints allowed)
		)
		(placement
			(enabled no)
			(sheetname "")
		)
		(fill
			(thermal_gap 0.5)
			(thermal_bridge_width 0.5)
			(island_removal_mode 0)
		)
		(polygon
			(pts
				(xy 311.862978 -291.466524) (xy 311.862978 -291.022786) (xy 314.188094 -291.022786) (xy 314.188094 -291.466524)
			)
		)
	)
	(zone
		(layer "F.Cu")
		(hatch none 0.5)
		(connect_pads
			(clearance 0)
		)
		(min_thickness 0.25)
		(keepout
			(tracks allowed)
			(vias allowed)
			(pads allowed)
			(copperpour allowed)
			(footprints allowed)
		)
		(placement
			(enabled no)
			(sheetname "")
		)
		(fill
			(thermal_gap 0.5)
			(thermal_bridge_width 0.5)
			(island_removal_mode 0)
		)
		(polygon
			(pts
				(xy 409.831794 -263.305036) (xy 409.831794 -263.076436) (xy 411.863794 -263.076436) (xy 411.863794 -263.305036)
			)
		)
	)
	(zone
		(layer "F.Cu")
		(hatch none 0.5)
		(connect_pads
			(clearance 0)
		)
		(min_thickness 0.25)
		(keepout
			(tracks allowed)
			(vias allowed)
			(pads allowed)
			(copperpour allowed)
			(footprints not_allowed)
		)
		(placement
			(enabled no)
			(sheetname "")
		)
		(fill
			(thermal_gap 0.5)
			(thermal_bridge_width 0.5)
			(island_removal_mode 0)
		)
		(polygon
			(pts
				(arc
					(start 11.726672 -28.754324)
					(mid 12.400909 -27.358704)
					(end 13.749528 -26.594816)
				)
				(arc
					(start 13.749528 -26.594816)
					(mid 11.807805 -15.905617)
					(end 0.999998 -17.008602)
				)
				(arc
					(start 0.999998 -27.591512)
					(mid 6.137804 -30.253378)
					(end 11.726672 -28.754324)
				)
			)
		)
	)
	(zone
		(layer "F.Cu")
		(hatch none 0.5)
		(connect_pads
			(clearance 0)
		)
		(min_thickness 0.25)
		(keepout
			(tracks allowed)
			(vias allowed)
			(pads allowed)
			(copperpour allowed)
			(footprints allowed)
		)
		(placement
			(enabled no)
			(sheetname "")
		)
		(fill
			(thermal_gap 0.5)
			(thermal_bridge_width 0.5)
			(island_removal_mode 0)
		)
		(polygon
			(pts
				(xy 14.560042 -309.316628) (xy 14.560042 -308.87289) (xy 16.885158 -308.87289) (xy 16.885158 -309.316628)
			)
		)
	)
	(zone
		(layer "F.Cu")
		(hatch none 0.5)
		(connect_pads
			(clearance 0)
		)
		(min_thickness 0.25)
		(keepout
			(tracks allowed)
			(vias allowed)
			(pads allowed)
			(copperpour allowed)
			(footprints allowed)
		)
		(placement
			(enabled no)
			(sheetname "")
		)
		(fill
			(thermal_gap 0.5)
			(thermal_bridge_width 0.5)
			(island_removal_mode 0)
		)
		(polygon
			(pts
				(xy 138.32332 -282.506928) (xy 138.61034 -282.506928) (xy 138.64082 -282.476448) (xy 138.64082 -281.849068)
				(xy 138.55446 -281.762708) (xy 138.3665 -281.762708) (xy 138.29284 -281.836368) (xy 138.29284 -282.476448)
			)
		)
	)
	(zone
		(layer "F.Cu")
		(hatch none 0.5)
		(connect_pads
			(clearance 0)
		)
		(min_thickness 0.25)
		(keepout
			(tracks allowed)
			(vias allowed)
			(pads allowed)
			(copperpour allowed)
			(footprints allowed)
		)
		(placement
			(enabled no)
			(sheetname "")
		)
		(fill
			(thermal_gap 0.5)
			(thermal_bridge_width 0.5)
			(island_removal_mode 0)
		)
		(polygon
			(pts
				(xy 179.011326 -269.026132) (xy 179.011326 -269.254732) (xy 179.011326 -269.700756) (xy 176.930558 -269.700756)
				(xy 176.930558 -268.423136) (xy 179.011326 -268.423136)
			)
		)
	)
	(zone
		(layer "F.Cu")
		(hatch none 0.5)
		(connect_pads
			(clearance 0)
		)
		(min_thickness 0.25)
		(keepout
			(tracks allowed)
			(vias allowed)
			(pads allowed)
			(copperpour allowed)
			(footprints allowed)
		)
		(placement
			(enabled no)
			(sheetname "")
		)
		(fill
			(thermal_gap 0.5)
			(thermal_bridge_width 0.5)
			(island_removal_mode 0)
		)
		(polygon
			(pts
				(xy 59.822842 -311.01665) (xy 59.822842 -310.572912) (xy 62.147958 -310.572912) (xy 62.147958 -311.01665)
			)
		)
	)
	(zone
		(layer "F.Cu")
		(hatch none 0.5)
		(connect_pads
			(clearance 0)
		)
		(min_thickness 0.25)
		(keepout
			(tracks allowed)
			(vias allowed)
			(pads allowed)
			(copperpour allowed)
			(footprints allowed)
		)
		(placement
			(enabled no)
			(sheetname "")
		)
		(fill
			(thermal_gap 0.5)
			(thermal_bridge_width 0.5)
			(island_removal_mode 0)
		)
		(polygon
			(pts
				(xy 210.598258 -233.555032) (xy 210.598258 -233.326432) (xy 212.630258 -233.326432) (xy 212.630258 -233.555032)
			)
		)
	)
	(zone
		(layer "F.Cu")
		(hatch none 0.5)
		(connect_pads
			(clearance 0)
		)
		(min_thickness 0.25)
		(keepout
			(tracks allowed)
			(vias allowed)
			(pads allowed)
			(copperpour allowed)
			(footprints allowed)
		)
		(placement
			(enabled no)
			(sheetname "")
		)
		(fill
			(thermal_gap 0.5)
			(thermal_bridge_width 0.5)
			(island_removal_mode 0)
		)
		(polygon
			(pts
				(xy 192.066926 -260.754876) (xy 192.066926 -260.526276) (xy 194.098926 -260.526276) (xy 194.098926 -260.754876)
			)
		)
	)
	(zone
		(layer "F.Cu")
		(hatch none 0.5)
		(connect_pads
			(clearance 0)
		)
		(min_thickness 0.25)
		(keepout
			(tracks allowed)
			(vias allowed)
			(pads allowed)
			(copperpour allowed)
			(footprints allowed)
		)
		(placement
			(enabled no)
			(sheetname "")
		)
		(fill
			(thermal_gap 0.5)
			(thermal_bridge_width 0.5)
			(island_removal_mode 0)
		)
		(polygon
			(pts
				(xy 11.08964 -108.991908) (xy 11.08964 -107.889548) (xy 13.02512 -107.889548) (xy 13.02512 -108.991908)
			)
		)
	)
	(zone
		(layer "F.Cu")
		(hatch none 0.5)
		(connect_pads
			(clearance 0)
		)
		(min_thickness 0.25)
		(keepout
			(tracks allowed)
			(vias allowed)
			(pads allowed)
			(copperpour allowed)
			(footprints allowed)
		)
		(placement
			(enabled no)
			(sheetname "")
		)
		(fill
			(thermal_gap 0.5)
			(thermal_bridge_width 0.5)
			(island_removal_mode 0)
		)
		(polygon
			(pts
				(xy 327.762362 -342.169242) (xy 325.946262 -342.169242) (xy 325.946262 -340.790022) (xy 327.762362 -340.790022)
			)
		)
	)
	(zone
		(layer "F.Cu")
		(hatch none 0.5)
		(connect_pads
			(clearance 0)
		)
		(min_thickness 0.25)
		(keepout
			(tracks allowed)
			(vias allowed)
			(pads allowed)
			(copperpour allowed)
			(footprints allowed)
		)
		(placement
			(enabled no)
			(sheetname "")
		)
		(fill
			(thermal_gap 0.5)
			(thermal_bridge_width 0.5)
			(island_removal_mode 0)
		)
		(polygon
			(pts
				(xy 210.598258 -197.854824) (xy 210.598258 -197.626224) (xy 212.630258 -197.626224) (xy 212.630258 -197.854824)
			)
		)
	)
	(zone
		(layer "F.Cu")
		(hatch none 0.5)
		(connect_pads
			(clearance 0)
		)
		(min_thickness 0.25)
		(keepout
			(tracks allowed)
			(vias allowed)
			(pads allowed)
			(copperpour allowed)
			(footprints allowed)
		)
		(placement
			(enabled no)
			(sheetname "")
		)
		(fill
			(thermal_gap 0.5)
			(thermal_bridge_width 0.5)
			(island_removal_mode 0)
		)
		(polygon
			(pts
				(xy 29.647642 -247.26646) (xy 29.647642 -246.822722) (xy 31.972758 -246.822722) (xy 31.972758 -247.26646)
			)
		)
	)
	(zone
		(layer "F.Cu")
		(hatch none 0.5)
		(connect_pads
			(clearance 0)
		)
		(min_thickness 0.25)
		(keepout
			(tracks allowed)
			(vias allowed)
			(pads allowed)
			(copperpour allowed)
			(footprints allowed)
		)
		(placement
			(enabled no)
			(sheetname "")
		)
		(fill
			(thermal_gap 0.5)
			(thermal_bridge_width 0.5)
			(island_removal_mode 0)
		)
		(polygon
			(pts
				(xy 192.066926 -272.42643) (xy 194.098926 -272.42643) (xy 194.098926 -272.428716) (xy 194.277742 -272.428716)
				(xy 194.277742 -272.665952) (xy 194.415664 -272.665952) (xy 194.458844 -272.709132) (xy 194.458844 -272.841974)
				(xy 194.458844 -273.146012) (xy 194.3862 -273.218656) (xy 191.845946 -273.218656) (xy 191.704722 -273.077432)
				(xy 191.704722 -272.880328) (xy 191.786256 -272.798794) (xy 191.786256 -272.42643) (xy 191.883792 -272.42643)
				(xy 191.930782 -272.42643)
			)
		)
	)
	(zone
		(layer "F.Cu")
		(hatch none 0.5)
		(connect_pads
			(clearance 0)
		)
		(min_thickness 0.25)
		(keepout
			(tracks allowed)
			(vias allowed)
			(pads allowed)
			(copperpour allowed)
			(footprints allowed)
		)
		(placement
			(enabled no)
			(sheetname "")
		)
		(fill
			(thermal_gap 0.5)
			(thermal_bridge_width 0.5)
			(island_removal_mode 0)
		)
		(polygon
			(pts
				(xy 274.143978 -220.9165) (xy 274.143978 -220.472762) (xy 276.469094 -220.472762) (xy 276.469094 -220.9165)
			)
		)
	)
	(zone
		(layer "F.Cu")
		(hatch none 0.5)
		(connect_pads
			(clearance 0)
		)
		(min_thickness 0.25)
		(keepout
			(tracks allowed)
			(vias allowed)
			(pads allowed)
			(copperpour allowed)
			(footprints allowed)
		)
		(placement
			(enabled no)
			(sheetname "")
		)
		(fill
			(thermal_gap 0.5)
			(thermal_bridge_width 0.5)
			(island_removal_mode 0)
		)
		(polygon
			(pts
				(xy 375.3739 -362.049568) (xy 375.3739 -362.361988) (xy 375.69648 -362.684568) (xy 376.87758 -362.684568)
				(xy 377.86818 -361.693968) (xy 377.86818 -360.774488) (xy 376.98172 -359.888028) (xy 374.28932 -359.888028)
				(xy 374.12168 -360.055668) (xy 374.12168 -360.797348)
			)
		)
	)
	(zone
		(layer "F.Cu")
		(hatch none 0.5)
		(connect_pads
			(clearance 0)
		)
		(min_thickness 0.25)
		(keepout
			(tracks allowed)
			(vias allowed)
			(pads allowed)
			(copperpour allowed)
			(footprints not_allowed)
		)
		(placement
			(enabled no)
			(sheetname "")
		)
		(fill
			(thermal_gap 0.5)
			(thermal_bridge_width 0.5)
			(island_removal_mode 0)
		)
		(polygon
			(pts
				(arc
					(start 233.849926 -352.49993)
					(mid 236.650022 -349.699834)
					(end 239.450118 -352.49993)
				)
				(arc
					(start 239.450118 -352.49993)
					(mid 236.650022 -355.300026)
					(end 233.849926 -352.49993)
				)
			)
		)
	)
	(zone
		(layer "F.Cu")
		(hatch none 0.5)
		(connect_pads
			(clearance 0)
		)
		(min_thickness 0.25)
		(keepout
			(tracks allowed)
			(vias allowed)
			(pads allowed)
			(copperpour allowed)
			(footprints allowed)
		)
		(placement
			(enabled no)
			(sheetname "")
		)
		(fill
			(thermal_gap 0.5)
			(thermal_bridge_width 0.5)
			(island_removal_mode 0)
		)
		(polygon
			(pts
				(xy 20.612862 -18.570702) (xy 20.612862 -15.436088) (xy 22.391624 -15.436088) (xy 22.391624 -18.570702)
			)
		)
	)
	(zone
		(layer "F.Cu")
		(hatch none 0.5)
		(connect_pads
			(clearance 0)
		)
		(min_thickness 0.25)
		(keepout
			(tracks allowed)
			(vias allowed)
			(pads allowed)
			(copperpour allowed)
			(footprints allowed)
		)
		(placement
			(enabled no)
			(sheetname "")
		)
		(fill
			(thermal_gap 0.5)
			(thermal_bridge_width 0.5)
			(island_removal_mode 0)
		)
		(polygon
			(pts
				(xy 157.791658 -222.505016) (xy 157.791658 -222.276416) (xy 159.823658 -222.276416) (xy 159.823658 -222.505016)
			)
		)
	)
	(zone
		(layer "F.Cu")
		(hatch none 0.5)
		(connect_pads
			(clearance 0)
		)
		(min_thickness 0.25)
		(keepout
			(tracks allowed)
			(vias allowed)
			(pads allowed)
			(copperpour allowed)
			(footprints allowed)
		)
		(placement
			(enabled no)
			(sheetname "")
		)
		(fill
			(thermal_gap 0.5)
			(thermal_bridge_width 0.5)
			(island_removal_mode 0)
		)
		(polygon
			(pts
				(xy 292.67531 -287.216596) (xy 292.67531 -286.772858) (xy 295.000426 -286.772858) (xy 295.000426 -287.216596)
			)
		)
	)
	(zone
		(layer "F.Cu")
		(hatch none 0.5)
		(connect_pads
			(clearance 0)
		)
		(min_thickness 0.25)
		(keepout
			(tracks allowed)
			(vias allowed)
			(pads allowed)
			(copperpour allowed)
			(footprints allowed)
		)
		(placement
			(enabled no)
			(sheetname "")
		)
		(fill
			(thermal_gap 0.5)
			(thermal_bridge_width 0.5)
			(island_removal_mode 0)
		)
		(polygon
			(pts
				(xy 274.143978 -260.866636) (xy 274.143978 -260.422898) (xy 276.469094 -260.422898) (xy 276.469094 -260.866636)
			)
		)
	)
	(zone
		(layer "F.Cu")
		(hatch none 0.5)
		(connect_pads
			(clearance 0)
		)
		(min_thickness 0.25)
		(keepout
			(tracks allowed)
			(vias allowed)
			(pads allowed)
			(copperpour allowed)
			(footprints allowed)
		)
		(placement
			(enabled no)
			(sheetname "")
		)
		(fill
			(thermal_gap 0.5)
			(thermal_bridge_width 0.5)
			(island_removal_mode 0)
		)
		(polygon
			(pts
				(xy 428.363126 -202.105006) (xy 428.363126 -201.876406) (xy 430.395126 -201.876406) (xy 430.395126 -202.105006)
			)
		)
	)
	(zone
		(layer "F.Cu")
		(hatch none 0.5)
		(connect_pads
			(clearance 0)
		)
		(min_thickness 0.25)
		(keepout
			(tracks allowed)
			(vias allowed)
			(pads allowed)
			(copperpour allowed)
			(footprints allowed)
		)
		(placement
			(enabled no)
			(sheetname "")
		)
		(fill
			(thermal_gap 0.5)
			(thermal_bridge_width 0.5)
			(island_removal_mode 0)
		)
		(polygon
			(pts
				(xy 409.831794 -289.654996) (xy 409.831794 -289.426396) (xy 411.863794 -289.426396) (xy 411.863794 -289.654996)
			)
		)
	)
	(zone
		(layer "F.Cu")
		(hatch none 0.5)
		(connect_pads
			(clearance 0)
		)
		(min_thickness 0.25)
		(keepout
			(tracks allowed)
			(vias allowed)
			(pads allowed)
			(copperpour allowed)
			(footprints not_allowed)
		)
		(placement
			(enabled no)
			(sheetname "")
		)
		(fill
			(thermal_gap 0.5)
			(thermal_bridge_width 0.5)
			(island_removal_mode 0)
		)
		(polygon
			(pts
				(arc
					(start 175.90008 -160.50006)
					(mid 167.900096 -168.500044)
					(end 159.900112 -160.50006)
				)
				(arc
					(start 159.900112 -160.50006)
					(mid 167.900096 -152.500076)
					(end 175.90008 -160.50006)
				)
			)
		)
	)
	(zone
		(layer "F.Cu")
		(hatch none 0.5)
		(connect_pads
			(clearance 0)
		)
		(min_thickness 0.25)
		(keepout
			(tracks allowed)
			(vias allowed)
			(pads allowed)
			(copperpour allowed)
			(footprints allowed)
		)
		(placement
			(enabled no)
			(sheetname "")
		)
		(fill
			(thermal_gap 0.5)
			(thermal_bridge_width 0.5)
			(island_removal_mode 0)
		)
		(polygon
			(pts
				(xy 86.21014 -284.950408) (xy 86.49716 -284.950408) (xy 86.52764 -284.919928) (xy 86.52764 -284.292548)
				(xy 86.44128 -284.206188) (xy 86.25332 -284.206188) (xy 86.17966 -284.279848) (xy 86.17966 -284.919928)
			)
		)
	)
	(zone
		(layer "F.Cu")
		(hatch none 0.5)
		(connect_pads
			(clearance 0)
		)
		(min_thickness 0.25)
		(keepout
			(tracks allowed)
			(vias allowed)
			(pads allowed)
			(copperpour allowed)
			(footprints allowed)
		)
		(placement
			(enabled no)
			(sheetname "")
		)
		(fill
			(thermal_gap 0.5)
			(thermal_bridge_width 0.5)
			(island_removal_mode 0)
		)
		(polygon
			(pts
				(xy 424.919394 -220.576394) (xy 426.951394 -220.576394) (xy 426.951394 -220.804994) (xy 424.919394 -220.804994)
				(xy 424.78325 -220.804994) (xy 424.73626 -220.804994) (xy 424.73626 -220.576394) (xy 424.78325 -220.576394)
			)
		)
	)
	(zone
		(layer "F.Cu")
		(hatch none 0.5)
		(connect_pads
			(clearance 0)
		)
		(min_thickness 0.25)
		(keepout
			(tracks allowed)
			(vias allowed)
			(pads allowed)
			(copperpour allowed)
			(footprints allowed)
		)
		(placement
			(enabled no)
			(sheetname "")
		)
		(fill
			(thermal_gap 0.5)
			(thermal_bridge_width 0.5)
			(island_removal_mode 0)
		)
		(polygon
			(pts
				(xy 192.066926 -291.126418) (xy 194.098926 -291.126418) (xy 194.098926 -291.355018) (xy 192.066926 -291.355018)
				(xy 191.930782 -291.355018) (xy 191.883792 -291.355018) (xy 191.883792 -291.126418) (xy 191.930782 -291.126418)
			)
		)
	)
	(zone
		(layer "F.Cu")
		(hatch none 0.5)
		(connect_pads
			(clearance 0)
		)
		(min_thickness 0.25)
		(keepout
			(tracks allowed)
			(vias allowed)
			(pads allowed)
			(copperpour allowed)
			(footprints allowed)
		)
		(placement
			(enabled no)
			(sheetname "")
		)
		(fill
			(thermal_gap 0.5)
			(thermal_bridge_width 0.5)
			(island_removal_mode 0)
		)
		(polygon
			(pts
				(xy 165.335458 -231.85501) (xy 165.335458 -231.62641) (xy 167.367458 -231.62641) (xy 167.367458 -231.85501)
			)
		)
	)
	(zone
		(layer "F.Cu")
		(hatch none 0.5)
		(connect_pads
			(clearance 0)
		)
		(min_thickness 0.25)
		(keepout
			(tracks allowed)
			(vias allowed)
			(pads allowed)
			(copperpour allowed)
			(footprints allowed)
		)
		(placement
			(enabled no)
			(sheetname "")
		)
		(fill
			(thermal_gap 0.5)
			(thermal_bridge_width 0.5)
			(island_removal_mode 0)
		)
		(polygon
			(pts
				(xy 440.006994 -246.304816) (xy 440.006994 -246.076216) (xy 442.038994 -246.076216) (xy 442.038994 -246.304816)
			)
		)
	)
	(zone
		(layer "F.Cu")
		(hatch none 0.5)
		(connect_pads
			(clearance 0)
		)
		(min_thickness 0.25)
		(keepout
			(tracks allowed)
			(vias allowed)
			(pads allowed)
			(copperpour allowed)
			(footprints allowed)
		)
		(placement
			(enabled no)
			(sheetname "")
		)
		(fill
			(thermal_gap 0.5)
			(thermal_bridge_width 0.5)
			(island_removal_mode 0)
		)
		(polygon
			(pts
				(xy 455.094594 -231.62641) (xy 457.126594 -231.62641) (xy 457.126594 -231.85501) (xy 455.094594 -231.85501)
				(xy 454.95845 -231.85501) (xy 454.91146 -231.85501) (xy 454.91146 -231.62641) (xy 454.95845 -231.62641)
			)
		)
	)
	(zone
		(layer "F.Cu")
		(hatch none 0.5)
		(connect_pads
			(clearance 0)
		)
		(min_thickness 0.25)
		(keepout
			(tracks allowed)
			(vias allowed)
			(pads allowed)
			(copperpour allowed)
			(footprints allowed)
		)
		(placement
			(enabled no)
			(sheetname "")
		)
		(fill
			(thermal_gap 0.5)
			(thermal_bridge_width 0.5)
			(island_removal_mode 0)
		)
		(polygon
			(pts
				(xy 455.094594 -286.026352) (xy 457.126594 -286.026352) (xy 457.126594 -286.254952) (xy 455.094594 -286.254952)
				(xy 454.95845 -286.254952) (xy 454.91146 -286.254952) (xy 454.91146 -286.026352) (xy 454.95845 -286.026352)
			)
		)
	)
	(zone
		(layer "F.Cu")
		(hatch none 0.5)
		(connect_pads
			(clearance 0)
		)
		(min_thickness 0.25)
		(keepout
			(tracks allowed)
			(vias allowed)
			(pads allowed)
			(copperpour allowed)
			(footprints allowed)
		)
		(placement
			(enabled no)
			(sheetname "")
		)
		(fill
			(thermal_gap 0.5)
			(thermal_bridge_width 0.5)
			(island_removal_mode 0)
		)
		(polygon
			(pts
				(xy 56.37911 -276.912832) (xy 56.37911 -276.572726) (xy 58.704226 -276.572726) (xy 58.758328 -276.572726)
				(xy 58.758328 -277.51278) (xy 56.253634 -277.51278) (xy 56.253634 -276.912832)
			)
		)
	)
	(zone
		(layer "F.Cu")
		(hatch none 0.5)
		(connect_pads
			(clearance 0)
		)
		(min_thickness 0.25)
		(keepout
			(tracks allowed)
			(vias allowed)
			(pads allowed)
			(copperpour allowed)
			(footprints allowed)
		)
		(placement
			(enabled no)
			(sheetname "")
		)
		(fill
			(thermal_gap 0.5)
			(thermal_bridge_width 0.5)
			(island_removal_mode 0)
		)
		(polygon
			(pts
				(xy 207.154526 -312.606944) (xy 209.186526 -312.606944) (xy 209.186526 -312.378344) (xy 207.154526 -312.378344)
				(xy 207.023208 -312.378344) (xy 206.9973 -312.378344) (xy 206.9973 -312.606944) (xy 207.023208 -312.606944)
			)
		)
	)
	(zone
		(layer "F.Cu")
		(hatch none 0.5)
		(connect_pads
			(clearance 0)
		)
		(min_thickness 0.25)
		(keepout
			(tracks allowed)
			(vias allowed)
			(pads allowed)
			(copperpour allowed)
			(footprints allowed)
		)
		(placement
			(enabled no)
			(sheetname "")
		)
		(fill
			(thermal_gap 0.5)
			(thermal_bridge_width 0.5)
			(island_removal_mode 0)
		)
		(polygon
			(pts
				(xy 409.831794 -213.155022) (xy 409.831794 -212.926422) (xy 411.863794 -212.926422) (xy 411.863794 -213.155022)
			)
		)
	)
	(zone
		(layer "F.Cu")
		(hatch none 0.5)
		(connect_pads
			(clearance 0)
		)
		(min_thickness 0.25)
		(keepout
			(tracks allowed)
			(vias allowed)
			(pads allowed)
			(copperpour allowed)
			(footprints allowed)
		)
		(placement
			(enabled no)
			(sheetname "")
		)
		(fill
			(thermal_gap 0.5)
			(thermal_bridge_width 0.5)
			(island_removal_mode 0)
		)
		(polygon
			(pts
				(xy 307.76291 -269.366492) (xy 307.76291 -268.922754) (xy 310.088026 -268.922754) (xy 310.088026 -269.366492)
			)
		)
	)
	(zone
		(layer "F.Cu")
		(hatch none 0.5)
		(connect_pads
			(clearance 0)
		)
		(min_thickness 0.25)
		(keepout
			(tracks allowed)
			(vias allowed)
			(pads allowed)
			(copperpour allowed)
			(footprints allowed)
		)
		(placement
			(enabled no)
			(sheetname "")
		)
		(fill
			(thermal_gap 0.5)
			(thermal_bridge_width 0.5)
			(island_removal_mode 0)
		)
		(polygon
			(pts
				(xy 14.560042 -236.216444) (xy 14.560042 -235.772706) (xy 16.885158 -235.772706) (xy 16.885158 -236.216444)
			)
		)
	)
	(zone
		(layer "F.Cu")
		(hatch none 0.5)
		(connect_pads
			(clearance 0)
		)
		(min_thickness 0.25)
		(keepout
			(tracks allowed)
			(vias allowed)
			(pads allowed)
			(copperpour allowed)
			(footprints not_allowed)
		)
		(placement
			(enabled no)
			(sheetname "")
		)
		(fill
			(thermal_gap 0.5)
			(thermal_bridge_width 0.5)
			(island_removal_mode 0)
		)
		(polygon
			(pts
				(arc
					(start 209.674968 -360.764074)
					(mid 213.67496 -356.764082)
					(end 217.674952 -360.764074)
				)
				(arc
					(start 217.674952 -360.764074)
					(mid 213.67496 -364.764066)
					(end 209.674968 -360.764074)
				)
			)
		)
	)
	(zone
		(layer "F.Cu")
		(hatch none 0.5)
		(connect_pads
			(clearance 0)
		)
		(min_thickness 0.25)
		(keepout
			(tracks allowed)
			(vias allowed)
			(pads allowed)
			(copperpour allowed)
			(footprints allowed)
		)
		(placement
			(enabled no)
			(sheetname "")
		)
		(fill
			(thermal_gap 0.5)
			(thermal_bridge_width 0.5)
			(island_removal_mode 0)
		)
		(polygon
			(pts
				(xy 405.731726 -214.85479) (xy 405.731726 -214.62619) (xy 407.763726 -214.62619) (xy 407.763726 -214.85479)
			)
		)
	)
	(zone
		(layer "F.Cu")
		(hatch none 0.5)
		(connect_pads
			(clearance 0)
		)
		(min_thickness 0.25)
		(keepout
			(tracks allowed)
			(vias allowed)
			(pads allowed)
			(copperpour allowed)
			(footprints allowed)
		)
		(placement
			(enabled no)
			(sheetname "")
		)
		(fill
			(thermal_gap 0.5)
			(thermal_bridge_width 0.5)
			(island_removal_mode 0)
		)
		(polygon
			(pts
				(xy 333.11592 -218.534488) (xy 333.40294 -218.534488) (xy 333.43342 -218.504008) (xy 333.43342 -217.876628)
				(xy 333.34706 -217.790268) (xy 333.1591 -217.790268) (xy 333.08544 -217.863928) (xy 333.08544 -218.504008)
			)
		)
	)
	(zone
		(layer "F.Cu")
		(hatch none 0.5)
		(connect_pads
			(clearance 0)
		)
		(min_thickness 0.25)
		(keepout
			(tracks allowed)
			(vias allowed)
			(pads allowed)
			(copperpour allowed)
			(footprints allowed)
		)
		(placement
			(enabled no)
			(sheetname "")
		)
		(fill
			(thermal_gap 0.5)
			(thermal_bridge_width 0.5)
			(island_removal_mode 0)
		)
		(polygon
			(pts
				(xy 292.67531 -199.666606) (xy 292.67531 -199.222868) (xy 295.000426 -199.222868) (xy 295.000426 -199.666606)
			)
		)
	)
	(zone
		(layer "F.Cu")
		(hatch none 0.5)
		(connect_pads
			(clearance 0)
		)
		(min_thickness 0.25)
		(keepout
			(tracks allowed)
			(vias allowed)
			(pads allowed)
			(copperpour allowed)
			(footprints allowed)
		)
		(placement
			(enabled no)
			(sheetname "")
		)
		(fill
			(thermal_gap 0.5)
			(thermal_bridge_width 0.5)
			(island_removal_mode 0)
		)
		(polygon
			(pts
				(xy 124.117608 -333.586582) (xy 120.581928 -333.586582) (xy 120.581928 -331.503782) (xy 124.117608 -331.503782)
			)
		)
	)
	(zone
		(layer "F.Cu")
		(hatch none 0.5)
		(connect_pads
			(clearance 0)
		)
		(min_thickness 0.25)
		(keepout
			(tracks allowed)
			(vias allowed)
			(pads allowed)
			(copperpour allowed)
			(footprints allowed)
		)
		(placement
			(enabled no)
			(sheetname "")
		)
		(fill
			(thermal_gap 0.5)
			(thermal_bridge_width 0.5)
			(island_removal_mode 0)
		)
		(polygon
			(pts
				(xy 304.319178 -314.41644) (xy 304.319178 -313.972702) (xy 306.644294 -313.972702) (xy 306.644294 -314.41644)
			)
		)
	)
	(zone
		(layer "F.Cu")
		(hatch none 0.5)
		(connect_pads
			(clearance 0)
		)
		(min_thickness 0.25)
		(keepout
			(tracks allowed)
			(vias allowed)
			(pads allowed)
			(copperpour allowed)
			(footprints allowed)
		)
		(placement
			(enabled no)
			(sheetname "")
		)
		(fill
			(thermal_gap 0.5)
			(thermal_bridge_width 0.5)
			(island_removal_mode 0)
		)
		(polygon
			(pts
				(xy 195.510658 -295.604946) (xy 195.510658 -295.376346) (xy 197.542658 -295.376346) (xy 197.542658 -295.604946)
			)
		)
	)
	(zone
		(layer "F.Cu")
		(hatch none 0.5)
		(connect_pads
			(clearance 0)
		)
		(min_thickness 0.25)
		(keepout
			(tracks allowed)
			(vias allowed)
			(pads allowed)
			(copperpour allowed)
			(footprints allowed)
		)
		(placement
			(enabled no)
			(sheetname "")
		)
		(fill
			(thermal_gap 0.5)
			(thermal_bridge_width 0.5)
			(island_removal_mode 0)
		)
		(polygon
			(pts
				(xy 195.510658 -216.554812) (xy 195.510658 -216.326212) (xy 197.542658 -216.326212) (xy 197.542658 -216.554812)
			)
		)
	)
	(zone
		(layer "F.Cu")
		(hatch none 0.5)
		(connect_pads
			(clearance 0)
		)
		(min_thickness 0.25)
		(keepout
			(tracks allowed)
			(vias allowed)
			(pads allowed)
			(copperpour allowed)
			(footprints allowed)
		)
		(placement
			(enabled no)
			(sheetname "")
		)
		(fill
			(thermal_gap 0.5)
			(thermal_bridge_width 0.5)
			(island_removal_mode 0)
		)
		(polygon
			(pts
				(xy 458.538326 -314.304934) (xy 458.538326 -314.076334) (xy 460.570326 -314.076334) (xy 460.570326 -314.304934)
			)
		)
	)
	(zone
		(layer "F.Cu")
		(hatch none 0.5)
		(connect_pads
			(clearance 0)
		)
		(min_thickness 0.25)
		(keepout
			(tracks allowed)
			(vias allowed)
			(pads allowed)
			(copperpour allowed)
			(footprints allowed)
		)
		(placement
			(enabled no)
			(sheetname "")
		)
		(fill
			(thermal_gap 0.5)
			(thermal_bridge_width 0.5)
			(island_removal_mode 0)
		)
		(polygon
			(pts
				(xy 420.885112 -153.077418) (xy 420.885112 -154.824938) (xy 418.949632 -154.824938) (xy 418.949632 -153.077418)
			)
		)
	)
	(zone
		(layer "F.Cu")
		(hatch none 0.5)
		(connect_pads
			(clearance 0)
		)
		(min_thickness 0.25)
		(keepout
			(tracks allowed)
			(vias allowed)
			(pads allowed)
			(copperpour allowed)
			(footprints allowed)
		)
		(placement
			(enabled no)
			(sheetname "")
		)
		(fill
			(thermal_gap 0.5)
			(thermal_bridge_width 0.5)
			(island_removal_mode 0)
		)
		(polygon
			(pts
				(xy 307.76291 -296.56659) (xy 307.76291 -296.122852) (xy 310.088026 -296.122852) (xy 310.088026 -296.56659)
			)
		)
	)
	(zone
		(layer "F.Cu")
		(hatch none 0.5)
		(connect_pads
			(clearance 0)
		)
		(min_thickness 0.25)
		(keepout
			(tracks allowed)
			(vias allowed)
			(pads allowed)
			(copperpour allowed)
			(footprints allowed)
		)
		(placement
			(enabled no)
			(sheetname "")
		)
		(fill
			(thermal_gap 0.5)
			(thermal_bridge_width 0.5)
			(island_removal_mode 0)
		)
		(polygon
			(pts
				(xy 165.335458 -265.854942) (xy 165.335458 -265.626342) (xy 167.367458 -265.626342) (xy 167.367458 -265.854942)
			)
		)
	)
	(zone
		(layer "F.Cu")
		(hatch none 0.5)
		(connect_pads
			(clearance 0)
		)
		(min_thickness 0.25)
		(keepout
			(tracks allowed)
			(vias allowed)
			(pads allowed)
			(copperpour allowed)
			(footprints allowed)
		)
		(placement
			(enabled no)
			(sheetname "")
		)
		(fill
			(thermal_gap 0.5)
			(thermal_bridge_width 0.5)
			(island_removal_mode 0)
		)
		(polygon
			(pts
				(xy 304.319178 -200.51649) (xy 304.319178 -200.072752) (xy 306.644294 -200.072752) (xy 306.644294 -200.51649)
			)
		)
	)
	(zone
		(layer "F.Cu")
		(hatch none 0.5)
		(connect_pads
			(clearance 0)
		)
		(min_thickness 0.25)
		(keepout
			(tracks allowed)
			(vias allowed)
			(pads allowed)
			(copperpour allowed)
			(footprints allowed)
		)
		(placement
			(enabled no)
			(sheetname "")
		)
		(fill
			(thermal_gap 0.5)
			(thermal_bridge_width 0.5)
			(island_removal_mode 0)
		)
		(polygon
			(pts
				(xy 388.561072 -20.291806) (xy 388.561072 -18.66138) (xy 390.152636 -18.66138) (xy 390.152636 -20.291806)
			)
		)
	)
	(zone
		(layer "F.Cu")
		(hatch none 0.5)
		(connect_pads
			(clearance 0)
		)
		(min_thickness 0.25)
		(keepout
			(tracks allowed)
			(vias allowed)
			(pads allowed)
			(copperpour allowed)
			(footprints allowed)
		)
		(placement
			(enabled no)
			(sheetname "")
		)
		(fill
			(thermal_gap 0.5)
			(thermal_bridge_width 0.5)
			(island_removal_mode 0)
		)
		(polygon
			(pts
				(xy 210.598258 -299.00499) (xy 210.598258 -298.77639) (xy 212.630258 -298.77639) (xy 212.630258 -299.00499)
			)
		)
	)
	(zone
		(layer "F.Cu")
		(hatch none 0.5)
		(connect_pads
			(clearance 0)
		)
		(min_thickness 0.25)
		(keepout
			(tracks not_allowed)
			(vias allowed)
			(pads allowed)
			(copperpour not_allowed)
			(footprints allowed)
		)
		(placement
			(enabled no)
			(sheetname "")
		)
		(fill
			(thermal_gap 0.5)
			(thermal_bridge_width 0.5)
			(island_removal_mode 0)
		)
		(polygon
			(pts
				(xy 430.46904 -124.277628) (xy 430.62144 -124.277628) (xy 430.62144 -120.956578) (xy 430.46904 -120.956578)
			)
		)
	)
	(zone
		(layer "F.Cu")
		(hatch none 0.5)
		(connect_pads
			(clearance 0)
		)
		(min_thickness 0.25)
		(keepout
			(tracks allowed)
			(vias allowed)
			(pads allowed)
			(copperpour allowed)
			(footprints allowed)
		)
		(placement
			(enabled no)
			(sheetname "")
		)
		(fill
			(thermal_gap 0.5)
			(thermal_bridge_width 0.5)
			(island_removal_mode 0)
		)
		(polygon
			(pts
				(xy 455.094594 -295.376346) (xy 457.126594 -295.376346) (xy 457.126594 -295.604946) (xy 455.094594 -295.604946)
				(xy 454.95845 -295.604946) (xy 454.91146 -295.604946) (xy 454.91146 -295.376346) (xy 454.95845 -295.376346)
			)
		)
	)
	(zone
		(layer "F.Cu")
		(hatch none 0.5)
		(connect_pads
			(clearance 0)
		)
		(min_thickness 0.25)
		(keepout
			(tracks allowed)
			(vias allowed)
			(pads allowed)
			(copperpour allowed)
			(footprints allowed)
		)
		(placement
			(enabled no)
			(sheetname "")
		)
		(fill
			(thermal_gap 0.5)
			(thermal_bridge_width 0.5)
			(island_removal_mode 0)
		)
		(polygon
			(pts
				(xy 356.02037 -359.517188) (xy 356.02037 -357.776526) (xy 357.935784 -357.776526) (xy 357.935784 -359.517188)
			)
		)
	)
	(zone
		(layer "F.Cu")
		(hatch none 0.5)
		(connect_pads
			(clearance 0)
		)
		(min_thickness 0.25)
		(keepout
			(tracks allowed)
			(vias allowed)
			(pads allowed)
			(copperpour allowed)
			(footprints allowed)
		)
		(placement
			(enabled no)
			(sheetname "")
		)
		(fill
			(thermal_gap 0.5)
			(thermal_bridge_width 0.5)
			(island_removal_mode 0)
		)
		(polygon
			(pts
				(xy 445.493902 -236.956854) (xy 443.461902 -236.956854) (xy 443.461902 -236.954568) (xy 443.283086 -236.954568)
				(xy 443.283086 -236.717332) (xy 443.146434 -236.58068) (xy 443.140846 -236.58068) (xy 443.101984 -236.541818)
				(xy 443.101984 -236.54131) (xy 443.101984 -236.318298) (xy 443.255654 -236.164628) (xy 445.714882 -236.164628)
				(xy 445.856106 -236.305852) (xy 445.856106 -236.502956) (xy 445.774572 -236.58449) (xy 445.690752 -236.66831)
				(xy 445.690752 -236.956854) (xy 445.677036 -236.956854) (xy 445.630046 -236.956854)
			)
		)
	)
	(zone
		(layer "F.Cu")
		(hatch none 0.5)
		(connect_pads
			(clearance 0)
		)
		(min_thickness 0.25)
		(keepout
			(tracks allowed)
			(vias allowed)
			(pads allowed)
			(copperpour allowed)
			(footprints allowed)
		)
		(placement
			(enabled no)
			(sheetname "")
		)
		(fill
			(thermal_gap 0.5)
			(thermal_bridge_width 0.5)
			(island_removal_mode 0)
		)
		(polygon
			(pts
				(xy 274.143978 -272.322798) (xy 276.469094 -272.322798) (xy 276.538944 -272.322798) (xy 276.538944 -273.258534)
				(xy 274.026376 -273.258534) (xy 274.026376 -272.322798)
			)
		)
	)
	(zone
		(layer "F.Cu")
		(hatch none 0.5)
		(connect_pads
			(clearance 0)
		)
		(min_thickness 0.25)
		(keepout
			(tracks allowed)
			(vias allowed)
			(pads allowed)
			(copperpour allowed)
			(footprints allowed)
		)
		(placement
			(enabled no)
			(sheetname "")
		)
		(fill
			(thermal_gap 0.5)
			(thermal_bridge_width 0.5)
			(island_removal_mode 0)
		)
		(polygon
			(pts
				(xy 56.228488 -319.243456) (xy 56.228488 -316.881256) (xy 58.844688 -316.881256) (xy 58.844688 -319.243456)
			)
		)
	)
	(zone
		(layer "F.Cu")
		(hatch none 0.5)
		(connect_pads
			(clearance 0)
		)
		(min_thickness 0.25)
		(keepout
			(tracks allowed)
			(vias allowed)
			(pads allowed)
			(copperpour allowed)
			(footprints not_allowed)
		)
		(placement
			(enabled no)
			(sheetname "")
		)
		(fill
			(thermal_gap 0.5)
			(thermal_bridge_width 0.5)
			(island_removal_mode 0)
		)
		(polygon
			(pts
				(arc
					(start 195.399914 -22.29993)
					(mid 203.399898 -14.299946)
					(end 211.399882 -22.29993)
				)
				(arc
					(start 211.399882 -22.29993)
					(mid 203.399898 -30.299914)
					(end 195.399914 -22.29993)
				)
			)
		)
	)
	(zone
		(layer "F.Cu")
		(hatch none 0.5)
		(connect_pads
			(clearance 0)
		)
		(min_thickness 0.25)
		(keepout
			(tracks allowed)
			(vias allowed)
			(pads allowed)
			(copperpour allowed)
			(footprints allowed)
		)
		(placement
			(enabled no)
			(sheetname "")
		)
		(fill
			(thermal_gap 0.5)
			(thermal_bridge_width 0.5)
			(island_removal_mode 0)
		)
		(polygon
			(pts
				(xy 161.891726 -260.754876) (xy 161.891726 -260.526276) (xy 163.923726 -260.526276) (xy 163.923726 -260.754876)
			)
		)
	)
	(zone
		(layer "F.Cu")
		(hatch none 0.5)
		(connect_pads
			(clearance 0)
		)
		(min_thickness 0.25)
		(keepout
			(tracks allowed)
			(vias allowed)
			(pads allowed)
			(copperpour allowed)
			(footprints allowed)
		)
		(placement
			(enabled no)
			(sheetname "")
		)
		(fill
			(thermal_gap 0.5)
			(thermal_bridge_width 0.5)
			(island_removal_mode 0)
		)
		(polygon
			(pts
				(xy 44.735242 -233.666538) (xy 44.735242 -233.2228) (xy 47.060358 -233.2228) (xy 47.060358 -233.666538)
			)
		)
	)
	(zone
		(layer "F.Cu")
		(hatch none 0.5)
		(connect_pads
			(clearance 0)
		)
		(min_thickness 0.25)
		(keepout
			(tracks allowed)
			(vias allowed)
			(pads allowed)
			(copperpour allowed)
			(footprints allowed)
		)
		(placement
			(enabled no)
			(sheetname "")
		)
		(fill
			(thermal_gap 0.5)
			(thermal_bridge_width 0.5)
			(island_removal_mode 0)
		)
		(polygon
			(pts
				(xy 158.65094 -48.9331) (xy 158.65094 -47.53356) (xy 160.55594 -47.53356) (xy 160.55594 -48.9331)
			)
		)
	)
	(zone
		(layer "F.Cu")
		(hatch none 0.5)
		(connect_pads
			(clearance 0)
		)
		(min_thickness 0.25)
		(keepout
			(tracks allowed)
			(vias allowed)
			(pads allowed)
			(copperpour allowed)
			(footprints allowed)
		)
		(placement
			(enabled no)
			(sheetname "")
		)
		(fill
			(thermal_gap 0.5)
			(thermal_bridge_width 0.5)
			(island_removal_mode 0)
		)
		(polygon
			(pts
				(xy 424.919394 -216.326466) (xy 426.951394 -216.326466) (xy 426.951394 -216.555066) (xy 424.919394 -216.555066)
				(xy 424.78325 -216.555066) (xy 424.73626 -216.555066) (xy 424.73626 -216.326466) (xy 424.78325 -216.326466)
			)
		)
	)
	(zone
		(layer "F.Cu")
		(hatch none 0.5)
		(connect_pads
			(clearance 0)
		)
		(min_thickness 0.25)
		(keepout
			(tracks allowed)
			(vias allowed)
			(pads allowed)
			(copperpour allowed)
			(footprints allowed)
		)
		(placement
			(enabled no)
			(sheetname "")
		)
		(fill
			(thermal_gap 0.5)
			(thermal_bridge_width 0.5)
			(island_removal_mode 0)
		)
		(polygon
			(pts
				(xy 259.056378 -284.666436) (xy 259.056378 -284.222698) (xy 261.381494 -284.222698) (xy 261.381494 -284.666436)
			)
		)
	)
	(zone
		(layer "F.Cu")
		(hatch none 0.5)
		(connect_pads
			(clearance 0)
		)
		(min_thickness 0.25)
		(keepout
			(tracks allowed)
			(vias allowed)
			(pads allowed)
			(copperpour allowed)
			(footprints allowed)
		)
		(placement
			(enabled no)
			(sheetname "")
		)
		(fill
			(thermal_gap 0.5)
			(thermal_bridge_width 0.5)
			(island_removal_mode 0)
		)
		(polygon
			(pts
				(xy 11.11631 -248.966482) (xy 11.11631 -248.522744) (xy 13.441426 -248.522744) (xy 13.441426 -248.966482)
			)
		)
	)
	(zone
		(layer "F.Cu")
		(hatch none 0.5)
		(connect_pads
			(clearance 0)
		)
		(min_thickness 0.25)
		(keepout
			(tracks allowed)
			(vias allowed)
			(pads allowed)
			(copperpour allowed)
			(footprints not_allowed)
		)
		(placement
			(enabled no)
			(sheetname "")
		)
		(fill
			(thermal_gap 0.5)
			(thermal_bridge_width 0.5)
			(island_removal_mode 0)
		)
		(polygon
			(pts
				(xy 221.861126 -144.763236) (xy 221.861126 -91.764358) (xy 2.999994 -91.764358) (xy 2.999994 -144.763236)
				(xy 19.455638 -144.763236) (xy 19.4564 -139.284964) (xy 40.456358 -139.26566) (xy 40.45585 -144.763236)
				(xy 183.455818 -144.763236) (xy 183.456326 -139.280646) (xy 204.456284 -139.282678) (xy 204.455776 -144.763236)
			)
		)
	)
	(zone
		(layer "F.Cu")
		(hatch none 0.5)
		(connect_pads
			(clearance 0)
		)
		(min_thickness 0.25)
		(keepout
			(tracks allowed)
			(vias allowed)
			(pads allowed)
			(copperpour allowed)
			(footprints allowed)
		)
		(placement
			(enabled no)
			(sheetname "")
		)
		(fill
			(thermal_gap 0.5)
			(thermal_bridge_width 0.5)
			(island_removal_mode 0)
		)
		(polygon
			(pts
				(xy 63.65748 -149.924008) (xy 63.65748 -145.776188) (xy 65.58534 -145.776188) (xy 65.58534 -149.924008)
			)
		)
	)
	(zone
		(layer "F.Cu")
		(hatch none 0.5)
		(connect_pads
			(clearance 0)
		)
		(min_thickness 0.25)
		(keepout
			(tracks allowed)
			(vias allowed)
			(pads allowed)
			(copperpour allowed)
			(footprints allowed)
		)
		(placement
			(enabled no)
			(sheetname "")
		)
		(fill
			(thermal_gap 0.5)
			(thermal_bridge_width 0.5)
			(island_removal_mode 0)
		)
		(polygon
			(pts
				(xy 56.37911 -207.316578) (xy 56.37911 -206.87284) (xy 58.704226 -206.87284) (xy 58.704226 -207.316578)
			)
		)
	)
	(zone
		(layer "F.Cu")
		(hatch none 0.5)
		(connect_pads
			(clearance 0)
		)
		(min_thickness 0.25)
		(keepout
			(tracks allowed)
			(vias allowed)
			(pads allowed)
			(copperpour allowed)
			(footprints allowed)
		)
		(placement
			(enabled no)
			(sheetname "")
		)
		(fill
			(thermal_gap 0.5)
			(thermal_bridge_width 0.5)
			(island_removal_mode 0)
		)
		(polygon
			(pts
				(xy 428.363126 -283.704792) (xy 428.363126 -283.476192) (xy 430.395126 -283.476192) (xy 430.395126 -283.704792)
			)
		)
	)
	(zone
		(layer "F.Cu")
		(hatch none 0.5)
		(connect_pads
			(clearance 0)
		)
		(min_thickness 0.25)
		(keepout
			(tracks allowed)
			(vias allowed)
			(pads allowed)
			(copperpour allowed)
			(footprints allowed)
		)
		(placement
			(enabled no)
			(sheetname "")
		)
		(fill
			(thermal_gap 0.5)
			(thermal_bridge_width 0.5)
			(island_removal_mode 0)
		)
		(polygon
			(pts
				(xy 292.67531 -245.566438) (xy 292.67531 -245.1227) (xy 295.000426 -245.1227) (xy 295.000426 -245.566438)
			)
		)
	)
	(zone
		(layer "F.Cu")
		(hatch none 0.5)
		(connect_pads
			(clearance 0)
		)
		(min_thickness 0.25)
		(keepout
			(tracks allowed)
			(vias allowed)
			(pads allowed)
			(copperpour allowed)
			(footprints allowed)
		)
		(placement
			(enabled no)
			(sheetname "")
		)
		(fill
			(thermal_gap 0.5)
			(thermal_bridge_width 0.5)
			(island_removal_mode 0)
		)
		(polygon
			(pts
				(xy 192.066926 -201.026268) (xy 194.098926 -201.026268) (xy 194.098926 -201.254868) (xy 192.066926 -201.254868)
				(xy 191.935608 -201.254868) (xy 191.9097 -201.254868) (xy 191.9097 -201.026268) (xy 191.935608 -201.026268)
			)
		)
	)
	(zone
		(layer "F.Cu")
		(hatch none 0.5)
		(connect_pads
			(clearance 0)
		)
		(min_thickness 0.25)
		(keepout
			(tracks allowed)
			(vias allowed)
			(pads allowed)
			(copperpour allowed)
			(footprints allowed)
		)
		(placement
			(enabled no)
			(sheetname "")
		)
		(fill
			(thermal_gap 0.5)
			(thermal_bridge_width 0.5)
			(island_removal_mode 0)
		)
		(polygon
			(pts
				(xy 277.58771 -314.41644) (xy 277.58771 -313.972702) (xy 279.912826 -313.972702) (xy 279.912826 -314.41644)
			)
		)
	)
	(zone
		(layer "F.Cu")
		(hatch none 0.5)
		(connect_pads
			(clearance 0)
		)
		(min_thickness 0.25)
		(keepout
			(tracks allowed)
			(vias allowed)
			(pads allowed)
			(copperpour allowed)
			(footprints not_allowed)
		)
		(placement
			(enabled no)
			(sheetname "")
		)
		(fill
			(thermal_gap 0.5)
			(thermal_bridge_width 0.5)
			(island_removal_mode 0)
		)
		(polygon
			(pts
				(xy 405.753062 -185.092086) (xy 464.65998 -185.092086) (xy 464.65998 -177.092102) (xy 405.753062 -177.092102)
			)
		)
	)
	(zone
		(layer "F.Cu")
		(hatch none 0.5)
		(connect_pads
			(clearance 0)
		)
		(min_thickness 0.25)
		(keepout
			(tracks allowed)
			(vias allowed)
			(pads allowed)
			(copperpour allowed)
			(footprints allowed)
		)
		(placement
			(enabled no)
			(sheetname "")
		)
		(fill
			(thermal_gap 0.5)
			(thermal_bridge_width 0.5)
			(island_removal_mode 0)
		)
		(polygon
			(pts
				(xy 413.275526 -286.254952) (xy 413.275526 -286.026352) (xy 415.307526 -286.026352) (xy 415.307526 -286.254952)
			)
		)
	)
	(zone
		(layer "F.Cu")
		(hatch none 0.5)
		(connect_pads
			(clearance 0)
		)
		(min_thickness 0.25)
		(keepout
			(tracks allowed)
			(vias allowed)
			(pads allowed)
			(copperpour allowed)
			(footprints allowed)
		)
		(placement
			(enabled no)
			(sheetname "")
		)
		(fill
			(thermal_gap 0.5)
			(thermal_bridge_width 0.5)
			(island_removal_mode 0)
		)
		(polygon
			(pts
				(xy 141.364462 -234.91317) (xy 140.792962 -234.91317) (xy 140.713968 -234.992164) (xy 140.475462 -234.992418)
				(xy 140.437362 -234.954318) (xy 140.437362 -233.812334) (xy 140.514832 -233.734864) (xy 140.514832 -233.151934)
				(xy 140.800328 -232.866438) (xy 140.800328 -232.725468) (xy 140.235178 -232.160318) (xy 140.235178 -232.108756)
				(xy 141.153388 -231.190546) (xy 141.153388 -231.08539) (xy 140.568426 -230.500428) (xy 140.568426 -230.397558)
				(xy 141.732508 -229.233476) (xy 141.732508 -229.070916) (xy 141.25829 -228.596698) (xy 141.11986 -228.596698)
				(xy 140.778738 -228.93782) (xy 140.719048 -228.93782) (xy 140.612114 -228.830886) (xy 140.612114 -228.78923)
				(xy 141.04239 -228.358954) (xy 141.04239 -228.297486) (xy 140.437362 -227.692458) (xy 140.437362 -227.6094)
				(xy 140.645642 -227.40112) (xy 140.645642 -227.327714) (xy 140.294614 -226.976686) (xy 140.294614 -226.877626)
				(xy 140.455396 -226.716844) (xy 140.455396 -226.657408) (xy 140.062712 -226.264724) (xy 140.062712 -226.227132)
				(xy 140.175488 -226.114356) (xy 140.175488 -225.760788) (xy 139.384532 -224.969832) (xy 139.32662 -224.969832)
				(xy 139.269216 -224.912428) (xy 139.269216 -218.228164) (xy 139.244832 -218.20378) (xy 139.244578 -214.835486)
				(xy 139.804648 -214.275416) (xy 139.804648 -214.27567) (xy 140.225526 -213.854792) (xy 140.225526 -213.529672)
				(xy 140.043154 -213.3473) (xy 140.043154 -212.89391) (xy 140.168122 -212.768942) (xy 140.168122 -212.056218)
				(xy 139.932664 -211.82076) (xy 139.932664 -210.965288) (xy 140.882116 -210.965034) (xy 140.976096 -210.871054)
				(xy 140.979398 -210.871054) (xy 141.0462 -210.804252) (xy 141.920976 -210.804252) (xy 141.920976 -209.646012)
				(xy 141.920976 -209.639154) (xy 142.000478 -209.559652) (xy 143.280638 -209.559652) (xy 143.298418 -209.577432)
				(xy 143.306038 -209.585052) (xy 143.306038 -209.887312) (xy 143.758158 -210.339432) (xy 143.758158 -210.5152)
				(xy 143.629126 -210.644232) (xy 143.146018 -211.12734) (xy 143.146018 -211.218272) (xy 143.474186 -211.54644)
				(xy 143.474186 -211.657946) (xy 143.474186 -212.043772) (xy 143.4465 -212.071458) (xy 143.4465 -212.942932)
				(xy 144.460976 -213.957408) (xy 144.460976 -214.089234) (xy 144.460976 -214.256112) (xy 144.705578 -214.500714)
				(xy 144.705578 -214.782654) (xy 145.69694 -215.774016) (xy 145.69694 -215.909398) (xy 145.69694 -216.400126)
				(xy 146.276822 -216.980008) (xy 146.65198 -216.980008) (xy 146.97456 -217.302588) (xy 147.039838 -217.367866)
				(xy 147.039838 -217.558112) (xy 146.74723 -217.85072) (xy 146.74723 -218.241626) (xy 147.014438 -218.508834)
				(xy 147.25523 -218.508834) (xy 147.25523 -219.310712) (xy 147.074128 -219.491814) (xy 147.074128 -220.574362)
				(xy 147.586446 -221.08668) (xy 147.586446 -221.15145) (xy 147.22983 -221.507812) (xy 147.22983 -229.047548)
			)
		)
	)
	(zone
		(layer "F.Cu")
		(hatch none 0.5)
		(connect_pads
			(clearance 0)
		)
		(min_thickness 0.25)
		(keepout
			(tracks allowed)
			(vias allowed)
			(pads allowed)
			(copperpour allowed)
			(footprints allowed)
		)
		(placement
			(enabled no)
			(sheetname "")
		)
		(fill
			(thermal_gap 0.5)
			(thermal_bridge_width 0.5)
			(island_removal_mode 0)
		)
		(polygon
			(pts
				(xy 194.110102 -238.656876) (xy 192.078102 -238.656876) (xy 192.078102 -238.65459) (xy 191.899286 -238.65459)
				(xy 191.899286 -238.417354) (xy 191.762634 -238.280702) (xy 191.757046 -238.280702) (xy 191.718184 -238.24184)
				(xy 191.718184 -238.241332) (xy 191.718184 -238.01832) (xy 191.871854 -237.86465) (xy 194.331082 -237.86465)
				(xy 194.472306 -238.005874) (xy 194.472306 -238.202978) (xy 194.390772 -238.284512) (xy 194.306952 -238.368332)
				(xy 194.306952 -238.656876) (xy 194.293236 -238.656876) (xy 194.246246 -238.656876)
			)
		)
	)
	(zone
		(layer "F.Cu")
		(hatch none 0.5)
		(connect_pads
			(clearance 0)
		)
		(min_thickness 0.25)
		(keepout
			(tracks allowed)
			(vias allowed)
			(pads allowed)
			(copperpour allowed)
			(footprints not_allowed)
		)
		(placement
			(enabled no)
			(sheetname "")
		)
		(fill
			(thermal_gap 0.5)
			(thermal_bridge_width 0.5)
			(island_removal_mode 0)
		)
		(polygon
			(pts
				(xy 405.753062 -339.092032) (xy 464.65998 -339.092032) (xy 464.65998 -331.092048) (xy 405.753062 -331.092048)
			)
		)
	)
	(zone
		(layer "F.Cu")
		(hatch none 0.5)
		(connect_pads
			(clearance 0)
		)
		(min_thickness 0.25)
		(keepout
			(tracks allowed)
			(vias allowed)
			(pads allowed)
			(copperpour allowed)
			(footprints allowed)
		)
		(placement
			(enabled no)
			(sheetname "")
		)
		(fill
			(thermal_gap 0.5)
			(thermal_bridge_width 0.5)
			(island_removal_mode 0)
		)
		(polygon
			(pts
				(xy 342.696546 -321.385184) (xy 342.696546 -319.083944) (xy 347.067886 -319.083944) (xy 347.067886 -321.385184)
			)
		)
	)
	(zone
		(layer "F.Cu")
		(hatch none 0.5)
		(connect_pads
			(clearance 0)
		)
		(min_thickness 0.25)
		(keepout
			(tracks allowed)
			(vias allowed)
			(pads allowed)
			(copperpour allowed)
			(footprints allowed)
		)
		(placement
			(enabled no)
			(sheetname "")
		)
		(fill
			(thermal_gap 0.5)
			(thermal_bridge_width 0.5)
			(island_removal_mode 0)
		)
		(polygon
			(pts
				(xy 44.735242 -268.516608) (xy 44.735242 -268.07287) (xy 47.060358 -268.07287) (xy 47.060358 -268.516608)
			)
		)
	)
	(zone
		(layer "F.Cu")
		(hatch none 0.5)
		(connect_pads
			(clearance 0)
		)
		(min_thickness 0.25)
		(keepout
			(tracks allowed)
			(vias allowed)
			(pads allowed)
			(copperpour allowed)
			(footprints allowed)
		)
		(placement
			(enabled no)
			(sheetname "")
		)
		(fill
			(thermal_gap 0.5)
			(thermal_bridge_width 0.5)
			(island_removal_mode 0)
		)
		(polygon
			(pts
				(xy 251.435616 -329.8317) (xy 252.301756 -329.8317) (xy 252.471936 -329.8317) (xy 252.471936 -331.18298)
				(xy 252.301756 -331.18298) (xy 251.435616 -331.18298) (xy 251.252736 -331.18298) (xy 251.186696 -331.18298)
				(xy 251.186696 -329.8317) (xy 251.252736 -329.8317)
			)
		)
	)
	(zone
		(layer "F.Cu")
		(hatch none 0.5)
		(connect_pads
			(clearance 0)
		)
		(min_thickness 0.25)
		(keepout
			(tracks allowed)
			(vias allowed)
			(pads allowed)
			(copperpour allowed)
			(footprints allowed)
		)
		(placement
			(enabled no)
			(sheetname "")
		)
		(fill
			(thermal_gap 0.5)
			(thermal_bridge_width 0.5)
			(island_removal_mode 0)
		)
		(polygon
			(pts
				(xy 156.456888 -404.802594) (xy 156.456888 -399.959576) (xy 158.341314 -399.959576) (xy 158.341314 -404.802594)
			)
		)
	)
	(zone
		(layer "F.Cu")
		(hatch none 0.5)
		(connect_pads
			(clearance 0)
		)
		(min_thickness 0.25)
		(keepout
			(tracks allowed)
			(vias allowed)
			(pads allowed)
			(copperpour allowed)
			(footprints allowed)
		)
		(placement
			(enabled no)
			(sheetname "")
		)
		(fill
			(thermal_gap 0.5)
			(thermal_bridge_width 0.5)
			(island_removal_mode 0)
		)
		(polygon
			(pts
				(xy 304.319178 -239.17275) (xy 306.644294 -239.17275) (xy 306.730908 -239.17275) (xy 306.730908 -240.120932)
				(xy 304.133758 -240.120932) (xy 304.133758 -239.17275)
			)
		)
	)
	(zone
		(layer "F.Cu")
		(hatch none 0.5)
		(connect_pads
			(clearance 0)
		)
		(min_thickness 0.25)
		(keepout
			(tracks allowed)
			(vias allowed)
			(pads allowed)
			(copperpour allowed)
			(footprints allowed)
		)
		(placement
			(enabled no)
			(sheetname "")
		)
		(fill
			(thermal_gap 0.5)
			(thermal_bridge_width 0.5)
			(island_removal_mode 0)
		)
		(polygon
			(pts
				(xy 63.900812 -205.616556) (xy 63.900812 -205.172818) (xy 66.212212 -205.172818) (xy 66.212212 -205.616556)
			)
		)
	)
	(zone
		(layer "F.Cu")
		(hatch none 0.5)
		(connect_pads
			(clearance 0)
		)
		(min_thickness 0.25)
		(keepout
			(tracks allowed)
			(vias allowed)
			(pads allowed)
			(copperpour allowed)
			(footprints allowed)
		)
		(placement
			(enabled no)
			(sheetname "")
		)
		(fill
			(thermal_gap 0.5)
			(thermal_bridge_width 0.5)
			(island_removal_mode 0)
		)
		(polygon
			(pts
				(xy 301.112682 -362.64596) (xy 297.577002 -362.64596) (xy 297.577002 -360.56316) (xy 301.112682 -360.56316)
			)
		)
	)
	(zone
		(layer "F.Cu")
		(hatch none 0.5)
		(connect_pads
			(clearance 0)
		)
		(min_thickness 0.25)
		(keepout
			(tracks allowed)
			(vias allowed)
			(pads allowed)
			(copperpour allowed)
			(footprints allowed)
		)
		(placement
			(enabled no)
			(sheetname "")
		)
		(fill
			(thermal_gap 0.5)
			(thermal_bridge_width 0.5)
			(island_removal_mode 0)
		)
		(polygon
			(pts
				(xy 413.275526 -280.305002) (xy 413.275526 -280.076402) (xy 415.307526 -280.076402) (xy 415.307526 -280.305002)
			)
		)
	)
	(zone
		(layer "F.Cu")
		(hatch none 0.5)
		(connect_pads
			(clearance 0)
		)
		(min_thickness 0.25)
		(keepout
			(tracks allowed)
			(vias allowed)
			(pads allowed)
			(copperpour allowed)
			(footprints allowed)
		)
		(placement
			(enabled no)
			(sheetname "")
		)
		(fill
			(thermal_gap 0.5)
			(thermal_bridge_width 0.5)
			(island_removal_mode 0)
		)
		(polygon
			(pts
				(xy 413.275526 -227.604828) (xy 413.275526 -227.376228) (xy 415.307526 -227.376228) (xy 415.307526 -227.604828)
			)
		)
	)
	(zone
		(layer "F.Cu")
		(hatch none 0.5)
		(connect_pads
			(clearance 0)
		)
		(min_thickness 0.25)
		(keepout
			(tracks allowed)
			(vias allowed)
			(pads allowed)
			(copperpour allowed)
			(footprints allowed)
		)
		(placement
			(enabled no)
			(sheetname "")
		)
		(fill
			(thermal_gap 0.5)
			(thermal_bridge_width 0.5)
			(island_removal_mode 0)
		)
		(polygon
			(pts
				(xy 413.275526 -282.854908) (xy 413.275526 -282.626308) (xy 415.307526 -282.626308) (xy 415.307526 -282.854908)
			)
		)
	)
	(zone
		(layer "F.Cu")
		(hatch none 0.5)
		(connect_pads
			(clearance 0)
		)
		(min_thickness 0.25)
		(keepout
			(tracks allowed)
			(vias allowed)
			(pads allowed)
			(copperpour allowed)
			(footprints allowed)
		)
		(placement
			(enabled no)
			(sheetname "")
		)
		(fill
			(thermal_gap 0.5)
			(thermal_bridge_width 0.5)
			(island_removal_mode 0)
		)
		(polygon
			(pts
				(xy 259.056378 -220.066616) (xy 259.056378 -219.622878) (xy 261.381494 -219.622878) (xy 261.381494 -220.066616)
			)
		)
	)
	(zone
		(layer "F.Cu")
		(hatch none 0.5)
		(connect_pads
			(clearance 0)
		)
		(min_thickness 0.25)
		(keepout
			(tracks not_allowed)
			(vias allowed)
			(pads allowed)
			(copperpour not_allowed)
			(footprints allowed)
		)
		(placement
			(enabled no)
			(sheetname "")
		)
		(fill
			(thermal_gap 0.5)
			(thermal_bridge_width 0.5)
			(island_removal_mode 0)
		)
		(polygon
			(pts
				(arc
					(start 320.099944 -160.50006)
					(mid 322.90004 -157.699964)
					(end 325.699882 -160.50006)
				)
				(arc
					(start 325.699882 -160.50006)
					(mid 322.90004 -163.299902)
					(end 320.099944 -160.50006)
				)
			)
		)
	)
	(zone
		(layer "F.Cu")
		(hatch none 0.5)
		(connect_pads
			(clearance 0)
		)
		(min_thickness 0.25)
		(keepout
			(tracks allowed)
			(vias allowed)
			(pads allowed)
			(copperpour allowed)
			(footprints allowed)
		)
		(placement
			(enabled no)
			(sheetname "")
		)
		(fill
			(thermal_gap 0.5)
			(thermal_bridge_width 0.5)
			(island_removal_mode 0)
		)
		(polygon
			(pts
				(xy 29.647642 -240.022888) (xy 31.972758 -240.022888) (xy 32.041338 -240.022888) (xy 32.041338 -240.934494)
				(xy 29.512768 -240.934494) (xy 29.512768 -240.022888)
			)
		)
	)
	(zone
		(layer "F.Cu")
		(hatch none 0.5)
		(connect_pads
			(clearance 0)
		)
		(min_thickness 0.25)
		(keepout
			(tracks allowed)
			(vias allowed)
			(pads allowed)
			(copperpour allowed)
			(footprints allowed)
		)
		(placement
			(enabled no)
			(sheetname "")
		)
		(fill
			(thermal_gap 0.5)
			(thermal_bridge_width 0.5)
			(island_removal_mode 0)
		)
		(polygon
			(pts
				(xy 180.423058 -297.304968) (xy 180.423058 -297.076368) (xy 182.455058 -297.076368) (xy 182.455058 -297.304968)
			)
		)
	)
	(zone
		(layer "F.Cu")
		(hatch none 0.5)
		(connect_pads
			(clearance 0)
		)
		(min_thickness 0.25)
		(keepout
			(tracks allowed)
			(vias allowed)
			(pads allowed)
			(copperpour allowed)
			(footprints allowed)
		)
		(placement
			(enabled no)
			(sheetname "")
		)
		(fill
			(thermal_gap 0.5)
			(thermal_bridge_width 0.5)
			(island_removal_mode 0)
		)
		(polygon
			(pts
				(xy 455.094594 -304.72634) (xy 457.126594 -304.72634) (xy 457.126594 -304.95494) (xy 455.094594 -304.95494)
				(xy 454.95845 -304.95494) (xy 454.91146 -304.95494) (xy 454.91146 -304.72634) (xy 454.95845 -304.72634)
			)
		)
	)
	(zone
		(layer "F.Cu")
		(hatch none 0.5)
		(connect_pads
			(clearance 0)
		)
		(min_thickness 0.25)
		(keepout
			(tracks allowed)
			(vias allowed)
			(pads allowed)
			(copperpour allowed)
			(footprints allowed)
		)
		(placement
			(enabled no)
			(sheetname "")
		)
		(fill
			(thermal_gap 0.5)
			(thermal_bridge_width 0.5)
			(island_removal_mode 0)
		)
		(polygon
			(pts
				(xy 180.423058 -310.90489) (xy 180.423058 -310.67629) (xy 182.455058 -310.67629) (xy 182.455058 -310.90489)
			)
		)
	)
	(zone
		(layer "F.Cu")
		(hatch none 0.5)
		(connect_pads
			(clearance 0)
		)
		(min_thickness 0.25)
		(keepout
			(tracks not_allowed)
			(vias allowed)
			(pads allowed)
			(copperpour not_allowed)
			(footprints allowed)
		)
		(placement
			(enabled no)
			(sheetname "")
		)
		(fill
			(thermal_gap 0.5)
			(thermal_bridge_width 0.5)
			(island_removal_mode 0)
		)
		(polygon
			(pts
				(arc
					(start 4.99999 -22.29993)
					(mid 6.999986 -20.299934)
					(end 8.999982 -22.29993)
				)
				(arc
					(start 8.999982 -22.29993)
					(mid 6.999986 -24.299926)
					(end 4.99999 -22.29993)
				)
			)
		)
	)
	(zone
		(layer "F.Cu")
		(hatch none 0.5)
		(connect_pads
			(clearance 0)
		)
		(min_thickness 0.25)
		(keepout
			(tracks not_allowed)
			(vias allowed)
			(pads allowed)
			(copperpour not_allowed)
			(footprints allowed)
		)
		(placement
			(enabled no)
			(sheetname "")
		)
		(fill
			(thermal_gap 0.5)
			(thermal_bridge_width 0.5)
			(island_removal_mode 0)
		)
		(polygon
			(pts
				(arc
					(start 113.609882 -431.360072)
					(mid 112.024922 -432.945032)
					(end 110.439962 -431.360072)
				)
				(arc
					(start 110.439962 -431.360072)
					(mid 112.024922 -429.775112)
					(end 113.609882 -431.360072)
				)
			)
		)
	)
	(zone
		(layer "F.Cu")
		(hatch none 0.5)
		(connect_pads
			(clearance 0)
		)
		(min_thickness 0.25)
		(keepout
			(tracks allowed)
			(vias allowed)
			(pads allowed)
			(copperpour allowed)
			(footprints allowed)
		)
		(placement
			(enabled no)
			(sheetname "")
		)
		(fill
			(thermal_gap 0.5)
			(thermal_bridge_width 0.5)
			(island_removal_mode 0)
		)
		(polygon
			(pts
				(xy 304.319178 -289.766502) (xy 304.319178 -289.322764) (xy 306.644294 -289.322764) (xy 306.644294 -289.766502)
			)
		)
	)
	(zone
		(layer "F.Cu")
		(hatch none 0.5)
		(connect_pads
			(clearance 0)
		)
		(min_thickness 0.25)
		(keepout
			(tracks allowed)
			(vias allowed)
			(pads allowed)
			(copperpour allowed)
			(footprints allowed)
		)
		(placement
			(enabled no)
			(sheetname "")
		)
		(fill
			(thermal_gap 0.5)
			(thermal_bridge_width 0.5)
			(island_removal_mode 0)
		)
		(polygon
			(pts
				(xy 207.154526 -197.626478) (xy 209.186526 -197.626478) (xy 209.186526 -197.855078) (xy 207.154526 -197.855078)
				(xy 207.018382 -197.855078) (xy 206.971392 -197.855078) (xy 206.971392 -197.626478) (xy 207.018382 -197.626478)
			)
		)
	)
	(zone
		(layer "F.Cu")
		(hatch none 0.5)
		(connect_pads
			(clearance 0)
		)
		(min_thickness 0.25)
		(keepout
			(tracks allowed)
			(vias allowed)
			(pads allowed)
			(copperpour allowed)
			(footprints allowed)
		)
		(placement
			(enabled no)
			(sheetname "")
		)
		(fill
			(thermal_gap 0.5)
			(thermal_bridge_width 0.5)
			(island_removal_mode 0)
		)
		(polygon
			(pts
				(xy 458.538326 -213.155022) (xy 458.538326 -212.926422) (xy 460.570326 -212.926422) (xy 460.570326 -213.155022)
			)
		)
	)
	(zone
		(layer "F.Cu")
		(hatch none 0.5)
		(connect_pads
			(clearance 0)
		)
		(min_thickness 0.25)
		(keepout
			(tracks allowed)
			(vias allowed)
			(pads allowed)
			(copperpour allowed)
			(footprints allowed)
		)
		(placement
			(enabled no)
			(sheetname "")
		)
		(fill
			(thermal_gap 0.5)
			(thermal_bridge_width 0.5)
			(island_removal_mode 0)
		)
		(polygon
			(pts
				(xy 139.330938 -235.170726) (xy 139.533884 -234.96778) (xy 139.533884 -234.9246) (xy 139.090146 -234.480862)
				(xy 138.967972 -234.480862) (xy 138.83513 -234.613958) (xy 138.83513 -234.718098) (xy 139.287758 -235.170726)
			)
		)
	)
	(zone
		(layer "F.Cu")
		(hatch none 0.5)
		(connect_pads
			(clearance 0)
		)
		(min_thickness 0.25)
		(keepout
			(tracks allowed)
			(vias allowed)
			(pads allowed)
			(copperpour allowed)
			(footprints allowed)
		)
		(placement
			(enabled no)
			(sheetname "")
		)
		(fill
			(thermal_gap 0.5)
			(thermal_bridge_width 0.5)
			(island_removal_mode 0)
		)
		(polygon
			(pts
				(xy 210.598258 -239.504982) (xy 210.598258 -239.276382) (xy 212.630258 -239.276382) (xy 212.630258 -239.504982)
			)
		)
	)
	(zone
		(layer "F.Cu")
		(hatch none 0.5)
		(connect_pads
			(clearance 0)
		)
		(min_thickness 0.25)
		(keepout
			(tracks allowed)
			(vias allowed)
			(pads allowed)
			(copperpour allowed)
			(footprints allowed)
		)
		(placement
			(enabled no)
			(sheetname "")
		)
		(fill
			(thermal_gap 0.5)
			(thermal_bridge_width 0.5)
			(island_removal_mode 0)
		)
		(polygon
			(pts
				(xy 56.37911 -286.366458) (xy 56.37911 -285.92272) (xy 58.704226 -285.92272) (xy 58.704226 -286.366458)
			)
		)
	)
	(zone
		(layer "F.Cu")
		(hatch none 0.5)
		(connect_pads
			(clearance 0)
		)
		(min_thickness 0.25)
		(keepout
			(tracks allowed)
			(vias allowed)
			(pads allowed)
			(copperpour allowed)
			(footprints allowed)
		)
		(placement
			(enabled no)
			(sheetname "")
		)
		(fill
			(thermal_gap 0.5)
			(thermal_bridge_width 0.5)
			(island_removal_mode 0)
		)
		(polygon
			(pts
				(xy 274.143978 -219.216478) (xy 274.143978 -218.77274) (xy 276.469094 -218.77274) (xy 276.469094 -219.216478)
			)
		)
	)
	(zone
		(layer "F.Cu")
		(hatch none 0.5)
		(connect_pads
			(clearance 0)
		)
		(min_thickness 0.25)
		(keepout
			(tracks allowed)
			(vias allowed)
			(pads allowed)
			(copperpour allowed)
			(footprints allowed)
		)
		(placement
			(enabled no)
			(sheetname "")
		)
		(fill
			(thermal_gap 0.5)
			(thermal_bridge_width 0.5)
			(island_removal_mode 0)
		)
		(polygon
			(pts
				(xy 137.72896 -216.898728) (xy 138.01598 -216.898728) (xy 138.04646 -216.868248) (xy 138.04646 -216.240868)
				(xy 137.9601 -216.154508) (xy 137.77214 -216.154508) (xy 137.69848 -216.228168) (xy 137.69848 -216.868248)
			)
		)
	)
	(zone
		(layer "F.Cu")
		(hatch none 0.5)
		(connect_pads
			(clearance 0)
		)
		(min_thickness 0.25)
		(keepout
			(tracks allowed)
			(vias allowed)
			(pads allowed)
			(copperpour allowed)
			(footprints allowed)
		)
		(placement
			(enabled no)
			(sheetname "")
		)
		(fill
			(thermal_gap 0.5)
			(thermal_bridge_width 0.5)
			(island_removal_mode 0)
		)
		(polygon
			(pts
				(xy 13.4239 -17.31518) (xy 13.4239 -16.3957) (xy 14.71422 -16.3957) (xy 14.71422 -17.31518)
			)
		)
	)
	(zone
		(layer "F.Cu")
		(hatch none 0.5)
		(connect_pads
			(clearance 0)
		)
		(min_thickness 0.25)
		(keepout
			(tracks allowed)
			(vias allowed)
			(pads allowed)
			(copperpour allowed)
			(footprints allowed)
		)
		(placement
			(enabled no)
			(sheetname "")
		)
		(fill
			(thermal_gap 0.5)
			(thermal_bridge_width 0.5)
			(island_removal_mode 0)
		)
		(polygon
			(pts
				(xy 314.12688 -238.766604) (xy 311.91708 -238.766604) (xy 311.522364 -238.766604) (xy 311.522364 -237.560104)
				(xy 314.457588 -237.560104) (xy 314.457588 -238.766604)
			)
		)
	)
	(zone
		(layer "F.Cu")
		(hatch none 0.5)
		(connect_pads
			(clearance 0)
		)
		(min_thickness 0.25)
		(keepout
			(tracks allowed)
			(vias allowed)
			(pads allowed)
			(copperpour allowed)
			(footprints allowed)
		)
		(placement
			(enabled no)
			(sheetname "")
		)
		(fill
			(thermal_gap 0.5)
			(thermal_bridge_width 0.5)
			(island_removal_mode 0)
		)
		(polygon
			(pts
				(xy 58.704226 -276.16658) (xy 56.37911 -276.16658) (xy 56.036464 -276.16658) (xy 56.036464 -274.911312)
				(xy 58.744612 -274.911312) (xy 58.744612 -276.16658)
			)
		)
	)
	(zone
		(layer "F.Cu")
		(hatch none 0.5)
		(connect_pads
			(clearance 0)
		)
		(min_thickness 0.25)
		(keepout
			(tracks allowed)
			(vias allowed)
			(pads allowed)
			(copperpour allowed)
			(footprints allowed)
		)
		(placement
			(enabled no)
			(sheetname "")
		)
		(fill
			(thermal_gap 0.5)
			(thermal_bridge_width 0.5)
			(island_removal_mode 0)
		)
		(polygon
			(pts
				(xy 274.143978 -252.366526) (xy 274.143978 -251.922788) (xy 276.469094 -251.922788) (xy 276.469094 -252.366526)
				(xy 276.469094 -252.880876) (xy 274.143978 -252.880876)
			)
		)
	)
	(zone
		(layer "F.Cu")
		(hatch none 0.5)
		(connect_pads
			(clearance 0)
		)
		(min_thickness 0.25)
		(keepout
			(tracks allowed)
			(vias allowed)
			(pads allowed)
			(copperpour allowed)
			(footprints allowed)
		)
		(placement
			(enabled no)
			(sheetname "")
		)
		(fill
			(thermal_gap 0.5)
			(thermal_bridge_width 0.5)
			(island_removal_mode 0)
		)
		(polygon
			(pts
				(xy 59.822842 -282.966414) (xy 59.822842 -282.522676) (xy 62.147958 -282.522676) (xy 62.147958 -282.966414)
			)
		)
	)
	(zone
		(layer "F.Cu")
		(hatch none 0.5)
		(connect_pads
			(clearance 0)
		)
		(min_thickness 0.25)
		(keepout
			(tracks allowed)
			(vias allowed)
			(pads allowed)
			(copperpour allowed)
			(footprints allowed)
		)
		(placement
			(enabled no)
			(sheetname "")
		)
		(fill
			(thermal_gap 0.5)
			(thermal_bridge_width 0.5)
			(island_removal_mode 0)
		)
		(polygon
			(pts
				(xy 458.538326 -302.405034) (xy 458.538326 -302.176434) (xy 460.570326 -302.176434) (xy 460.570326 -302.405034)
			)
		)
	)
	(zone
		(layer "F.Cu")
		(hatch none 0.5)
		(connect_pads
			(clearance 0)
		)
		(min_thickness 0.25)
		(keepout
			(tracks not_allowed)
			(vias allowed)
			(pads allowed)
			(copperpour not_allowed)
			(footprints allowed)
		)
		(placement
			(enabled no)
			(sheetname "")
		)
		(fill
			(thermal_gap 0.5)
			(thermal_bridge_width 0.5)
			(island_removal_mode 0)
		)
		(polygon
			(pts
				(arc
					(start 462.19999 -33.899856)
					(mid 464.799934 -36.4998)
					(end 467.399878 -33.899856)
				)
				(arc
					(start 467.399878 -32.29991)
					(mid 464.799934 -29.699966)
					(end 462.19999 -32.29991)
				)
			)
		)
	)
	(zone
		(layer "F.Cu")
		(hatch none 0.5)
		(connect_pads
			(clearance 0)
		)
		(min_thickness 0.25)
		(keepout
			(tracks allowed)
			(vias allowed)
			(pads allowed)
			(copperpour allowed)
			(footprints not_allowed)
		)
		(placement
			(enabled no)
			(sheetname "")
		)
		(fill
			(thermal_gap 0.5)
			(thermal_bridge_width 0.5)
			(island_removal_mode 0)
		)
		(polygon
			(pts
				(xy 197.474332 -14.780006) (xy 197.474332 -6.780022) (xy 208.47431 -6.780022) (xy 208.47431 -14.780006)
			)
		)
	)
	(zone
		(layer "F.Cu")
		(hatch none 0.5)
		(connect_pads
			(clearance 0)
		)
		(min_thickness 0.25)
		(keepout
			(tracks allowed)
			(vias allowed)
			(pads allowed)
			(copperpour allowed)
			(footprints allowed)
		)
		(placement
			(enabled no)
			(sheetname "")
		)
		(fill
			(thermal_gap 0.5)
			(thermal_bridge_width 0.5)
			(island_removal_mode 0)
		)
		(polygon
			(pts
				(xy 78.47076 -330.492608) (xy 78.47076 -328.298048) (xy 82.78368 -328.298048) (xy 82.78368 -330.492608)
			)
		)
	)
	(zone
		(layer "F.Cu")
		(hatch none 0.5)
		(connect_pads
			(clearance 0)
		)
		(min_thickness 0.25)
		(keepout
			(tracks allowed)
			(vias allowed)
			(pads allowed)
			(copperpour allowed)
			(footprints allowed)
		)
		(placement
			(enabled no)
			(sheetname "")
		)
		(fill
			(thermal_gap 0.5)
			(thermal_bridge_width 0.5)
			(island_removal_mode 0)
		)
		(polygon
			(pts
				(xy 192.066926 -220.576394) (xy 194.098926 -220.576394) (xy 194.098926 -220.804994) (xy 192.066926 -220.804994)
				(xy 191.930782 -220.804994) (xy 191.883792 -220.804994) (xy 191.883792 -220.576394) (xy 191.930782 -220.576394)
			)
		)
	)
	(zone
		(layer "F.Cu")
		(hatch none 0.5)
		(connect_pads
			(clearance 0)
		)
		(min_thickness 0.25)
		(keepout
			(tracks allowed)
			(vias allowed)
			(pads allowed)
			(copperpour allowed)
			(footprints allowed)
		)
		(placement
			(enabled no)
			(sheetname "")
		)
		(fill
			(thermal_gap 0.5)
			(thermal_bridge_width 0.5)
			(island_removal_mode 0)
		)
		(polygon
			(pts
				(xy 455.094594 -264.776204) (xy 457.126594 -264.776204) (xy 457.126594 -265.004804) (xy 455.094594 -265.004804)
				(xy 454.92797 -265.004804) (xy 454.92797 -264.776204)
			)
		)
	)
	(zone
		(layer "F.Cu")
		(hatch none 0.5)
		(connect_pads
			(clearance 0)
		)
		(min_thickness 0.25)
		(keepout
			(tracks allowed)
			(vias allowed)
			(pads allowed)
			(copperpour allowed)
			(footprints allowed)
		)
		(placement
			(enabled no)
			(sheetname "")
		)
		(fill
			(thermal_gap 0.5)
			(thermal_bridge_width 0.5)
			(island_removal_mode 0)
		)
		(polygon
			(pts
				(xy 165.335458 -308.354984) (xy 165.335458 -308.126384) (xy 167.367458 -308.126384) (xy 167.367458 -308.354984)
			)
		)
	)
	(zone
		(layer "F.Cu")
		(hatch none 0.5)
		(connect_pads
			(clearance 0)
		)
		(min_thickness 0.25)
		(keepout
			(tracks allowed)
			(vias allowed)
			(pads allowed)
			(copperpour allowed)
			(footprints allowed)
		)
		(placement
			(enabled no)
			(sheetname "")
		)
		(fill
			(thermal_gap 0.5)
			(thermal_bridge_width 0.5)
			(island_removal_mode 0)
		)
		(polygon
			(pts
				(xy 56.37911 -220.066616) (xy 56.37911 -219.622878) (xy 58.704226 -219.622878) (xy 58.704226 -220.066616)
			)
		)
	)
	(zone
		(layer "F.Cu")
		(hatch none 0.5)
		(connect_pads
			(clearance 0)
		)
		(min_thickness 0.25)
		(keepout
			(tracks allowed)
			(vias allowed)
			(pads allowed)
			(copperpour allowed)
			(footprints allowed)
		)
		(placement
			(enabled no)
			(sheetname "")
		)
		(fill
			(thermal_gap 0.5)
			(thermal_bridge_width 0.5)
			(island_removal_mode 0)
		)
		(polygon
			(pts
				(xy 29.647642 -299.966634) (xy 29.647642 -299.522896) (xy 31.972758 -299.522896) (xy 31.972758 -299.966634)
			)
		)
	)
	(zone
		(layer "F.Cu")
		(hatch none 0.5)
		(connect_pads
			(clearance 0)
		)
		(min_thickness 0.25)
		(keepout
			(tracks allowed)
			(vias allowed)
			(pads allowed)
			(copperpour allowed)
			(footprints allowed)
		)
		(placement
			(enabled no)
			(sheetname "")
		)
		(fill
			(thermal_gap 0.5)
			(thermal_bridge_width 0.5)
			(island_removal_mode 0)
		)
		(polygon
			(pts
				(xy 14.560042 -299.116496) (xy 14.560042 -298.672758) (xy 16.885158 -298.672758) (xy 16.885158 -299.116496)
			)
		)
	)
	(zone
		(layer "F.Cu")
		(hatch none 0.5)
		(connect_pads
			(clearance 0)
		)
		(min_thickness 0.25)
		(keepout
			(tracks allowed)
			(vias allowed)
			(pads allowed)
			(copperpour allowed)
			(footprints allowed)
		)
		(placement
			(enabled no)
			(sheetname "")
		)
		(fill
			(thermal_gap 0.5)
			(thermal_bridge_width 0.5)
			(island_removal_mode 0)
		)
		(polygon
			(pts
				(xy 180.423058 -198.704962) (xy 180.423058 -198.476362) (xy 182.455058 -198.476362) (xy 182.455058 -198.704962)
			)
		)
	)
	(zone
		(layer "F.Cu")
		(hatch none 0.5)
		(connect_pads
			(clearance 0)
		)
		(min_thickness 0.25)
		(keepout
			(tracks allowed)
			(vias allowed)
			(pads allowed)
			(copperpour allowed)
			(footprints allowed)
		)
		(placement
			(enabled no)
			(sheetname "")
		)
		(fill
			(thermal_gap 0.5)
			(thermal_bridge_width 0.5)
			(island_removal_mode 0)
		)
		(polygon
			(pts
				(xy 259.056378 -306.766468) (xy 259.056378 -306.32273) (xy 261.381494 -306.32273) (xy 261.381494 -306.766468)
			)
		)
	)
	(zone
		(layer "F.Cu")
		(hatch none 0.5)
		(connect_pads
			(clearance 0)
		)
		(min_thickness 0.25)
		(keepout
			(tracks allowed)
			(vias allowed)
			(pads allowed)
			(copperpour allowed)
			(footprints allowed)
		)
		(placement
			(enabled no)
			(sheetname "")
		)
		(fill
			(thermal_gap 0.5)
			(thermal_bridge_width 0.5)
			(island_removal_mode 0)
		)
		(polygon
			(pts
				(xy 64.002412 -266.816586) (xy 64.002412 -266.372848) (xy 66.186812 -266.372848) (xy 66.186812 -266.816586)
			)
		)
	)
	(zone
		(layer "F.Cu")
		(hatch none 0.5)
		(connect_pads
			(clearance 0)
		)
		(min_thickness 0.25)
		(keepout
			(tracks allowed)
			(vias allowed)
			(pads allowed)
			(copperpour allowed)
			(footprints allowed)
		)
		(placement
			(enabled no)
			(sheetname "")
		)
		(fill
			(thermal_gap 0.5)
			(thermal_bridge_width 0.5)
			(island_removal_mode 0)
		)
		(polygon
			(pts
				(xy 405.731726 -211.455) (xy 405.731726 -211.2264) (xy 407.763726 -211.2264) (xy 407.763726 -211.455)
			)
		)
	)
	(zone
		(layer "F.Cu")
		(hatch none 0.5)
		(connect_pads
			(clearance 0)
		)
		(min_thickness 0.25)
		(keepout
			(tracks allowed)
			(vias allowed)
			(pads allowed)
			(copperpour allowed)
			(footprints allowed)
		)
		(placement
			(enabled no)
			(sheetname "")
		)
		(fill
			(thermal_gap 0.5)
			(thermal_bridge_width 0.5)
			(island_removal_mode 0)
		)
		(polygon
			(pts
				(xy 428.363126 -208.054956) (xy 428.363126 -207.826356) (xy 430.395126 -207.826356) (xy 430.395126 -208.054956)
			)
		)
	)
	(zone
		(layer "F.Cu")
		(hatch none 0.5)
		(connect_pads
			(clearance 0)
		)
		(min_thickness 0.25)
		(keepout
			(tracks allowed)
			(vias allowed)
			(pads allowed)
			(copperpour allowed)
			(footprints allowed)
		)
		(placement
			(enabled no)
			(sheetname "")
		)
		(fill
			(thermal_gap 0.5)
			(thermal_bridge_width 0.5)
			(island_removal_mode 0)
		)
		(polygon
			(pts
				(xy 29.647642 -208.166462) (xy 29.647642 -207.722724) (xy 31.972758 -207.722724) (xy 31.972758 -208.166462)
			)
		)
	)
	(zone
		(layer "F.Cu")
		(hatch none 0.5)
		(connect_pads
			(clearance 0)
		)
		(min_thickness 0.25)
		(keepout
			(tracks allowed)
			(vias allowed)
			(pads allowed)
			(copperpour allowed)
			(footprints allowed)
		)
		(placement
			(enabled no)
			(sheetname "")
		)
		(fill
			(thermal_gap 0.5)
			(thermal_bridge_width 0.5)
			(island_removal_mode 0)
		)
		(polygon
			(pts
				(xy 304.42408 -245.566438) (xy 304.42408 -245.1227) (xy 306.55768 -245.1227) (xy 306.55768 -245.566438)
			)
		)
	)
	(zone
		(layer "F.Cu")
		(hatch none 0.5)
		(connect_pads
			(clearance 0)
		)
		(min_thickness 0.25)
		(keepout
			(tracks allowed)
			(vias allowed)
			(pads allowed)
			(copperpour allowed)
			(footprints allowed)
		)
		(placement
			(enabled no)
			(sheetname "")
		)
		(fill
			(thermal_gap 0.5)
			(thermal_bridge_width 0.5)
			(island_removal_mode 0)
		)
		(polygon
			(pts
				(xy 445.493902 -233.557064) (xy 443.461902 -233.557064) (xy 443.461902 -233.554778) (xy 443.283086 -233.554778)
				(xy 443.283086 -233.317542) (xy 443.145164 -233.317542) (xy 443.101984 -233.274362) (xy 443.101984 -233.14152)
				(xy 443.101984 -232.837482) (xy 443.174628 -232.764838) (xy 445.714882 -232.764838) (xy 445.856106 -232.906062)
				(xy 445.856106 -233.103166) (xy 445.774572 -233.1847) (xy 445.774572 -233.557064) (xy 445.677036 -233.557064)
				(xy 445.630046 -233.557064)
			)
		)
	)
	(zone
		(layer "F.Cu")
		(hatch none 0.5)
		(connect_pads
			(clearance 0)
		)
		(min_thickness 0.25)
		(keepout
			(tracks allowed)
			(vias allowed)
			(pads allowed)
			(copperpour allowed)
			(footprints allowed)
		)
		(placement
			(enabled no)
			(sheetname "")
		)
		(fill
			(thermal_gap 0.5)
			(thermal_bridge_width 0.5)
			(island_removal_mode 0)
		)
		(polygon
			(pts
				(xy 161.891726 -308.354984) (xy 161.891726 -308.126384) (xy 163.923726 -308.126384) (xy 163.923726 -308.354984)
			)
		)
	)
	(zone
		(layer "F.Cu")
		(hatch none 0.5)
		(connect_pads
			(clearance 0)
		)
		(min_thickness 0.25)
		(keepout
			(tracks allowed)
			(vias allowed)
			(pads allowed)
			(copperpour allowed)
			(footprints allowed)
		)
		(placement
			(enabled no)
			(sheetname "")
		)
		(fill
			(thermal_gap 0.5)
			(thermal_bridge_width 0.5)
			(island_removal_mode 0)
		)
		(polygon
			(pts
				(xy 84.277962 -234.096306) (xy 84.480908 -234.299252) (xy 84.524088 -234.299252) (xy 84.967826 -233.855514)
				(xy 84.967826 -233.73334) (xy 84.83473 -233.600498) (xy 84.73059 -233.600498) (xy 84.277962 -234.053126)
			)
		)
	)
	(zone
		(layer "F.Cu")
		(hatch none 0.5)
		(connect_pads
			(clearance 0)
		)
		(min_thickness 0.25)
		(keepout
			(tracks allowed)
			(vias allowed)
			(pads allowed)
			(copperpour allowed)
			(footprints allowed)
		)
		(placement
			(enabled no)
			(sheetname "")
		)
		(fill
			(thermal_gap 0.5)
			(thermal_bridge_width 0.5)
			(island_removal_mode 0)
		)
		(polygon
			(pts
				(xy 430.57572 -125.016768) (xy 430.57572 -120.980708) (xy 434.45684 -120.980708) (xy 434.45684 -125.016768)
			)
		)
	)
	(zone
		(layer "F.Cu")
		(hatch none 0.5)
		(connect_pads
			(clearance 0)
		)
		(min_thickness 0.25)
		(keepout
			(tracks allowed)
			(vias allowed)
			(pads allowed)
			(copperpour allowed)
			(footprints not_allowed)
		)
		(placement
			(enabled no)
			(sheetname "")
		)
		(fill
			(thermal_gap 0.5)
			(thermal_bridge_width 0.5)
			(island_removal_mode 0)
		)
		(polygon
			(pts
				(arc
					(start 463.300064 -440.989974)
					(mid 464.007169 -440.697081)
					(end 464.300062 -439.989976)
				)
				(arc
					(start 464.300062 -429.790606)
					(mid 462.853736 -428.703069)
					(end 461.199992 -427.96841)
				)
				(xy 461.199992 -428.885096)
				(arc
					(start 454.451466 -428.885096)
					(mid 452.117107 -431.202351)
					(end 450.912484 -434.263038)
				)
				(arc
					(start 450.912484 -434.263038)
					(mid 451.20118 -434.904052)
					(end 451.300088 -435.600094)
				)
				(arc
					(start 451.300088 -435.600094)
					(mid 451.20239 -436.291844)
					(end 450.917056 -436.92953)
				)
				(arc
					(start 450.917056 -436.92953)
					(mid 451.610394 -439.101667)
					(end 452.88835 -440.989974)
				)
			)
		)
	)
	(zone
		(layer "F.Cu")
		(hatch none 0.5)
		(connect_pads
			(clearance 0)
		)
		(min_thickness 0.25)
		(keepout
			(tracks allowed)
			(vias allowed)
			(pads allowed)
			(copperpour allowed)
			(footprints allowed)
		)
		(placement
			(enabled no)
			(sheetname "")
		)
		(fill
			(thermal_gap 0.5)
			(thermal_bridge_width 0.5)
			(island_removal_mode 0)
		)
		(polygon
			(pts
				(xy 176.979326 -201.026268) (xy 179.011326 -201.026268) (xy 179.011326 -201.254868) (xy 176.979326 -201.254868)
				(xy 176.848008 -201.254868) (xy 176.8221 -201.254868) (xy 176.8221 -201.026268) (xy 176.848008 -201.026268)
			)
		)
	)
	(zone
		(layer "F.Cu")
		(hatch none 0.5)
		(connect_pads
			(clearance 0)
		)
		(min_thickness 0.25)
		(keepout
			(tracks allowed)
			(vias allowed)
			(pads allowed)
			(copperpour allowed)
			(footprints allowed)
		)
		(placement
			(enabled no)
			(sheetname "")
		)
		(fill
			(thermal_gap 0.5)
			(thermal_bridge_width 0.5)
			(island_removal_mode 0)
		)
		(polygon
			(pts
				(xy 195.510658 -293.05504) (xy 195.510658 -292.82644) (xy 197.542658 -292.82644) (xy 197.542658 -293.05504)
			)
		)
	)
	(zone
		(layer "F.Cu")
		(hatch none 0.5)
		(connect_pads
			(clearance 0)
		)
		(min_thickness 0.25)
		(keepout
			(tracks allowed)
			(vias allowed)
			(pads allowed)
			(copperpour allowed)
			(footprints allowed)
		)
		(placement
			(enabled no)
			(sheetname "")
		)
		(fill
			(thermal_gap 0.5)
			(thermal_bridge_width 0.5)
			(island_removal_mode 0)
		)
		(polygon
			(pts
				(xy 176.979326 -291.126418) (xy 179.011326 -291.126418) (xy 179.011326 -291.355018) (xy 176.979326 -291.355018)
				(xy 176.843182 -291.355018) (xy 176.796192 -291.355018) (xy 176.796192 -291.126418) (xy 176.843182 -291.126418)
			)
		)
	)
	(zone
		(layer "F.Cu")
		(hatch none 0.5)
		(connect_pads
			(clearance 0)
		)
		(min_thickness 0.25)
		(keepout
			(tracks allowed)
			(vias allowed)
			(pads allowed)
			(copperpour allowed)
			(footprints allowed)
		)
		(placement
			(enabled no)
			(sheetname "")
		)
		(fill
			(thermal_gap 0.5)
			(thermal_bridge_width 0.5)
			(island_removal_mode 0)
		)
		(polygon
			(pts
				(xy 29.647642 -296.56659) (xy 29.647642 -296.122852) (xy 31.972758 -296.122852) (xy 31.972758 -296.56659)
			)
		)
	)
	(zone
		(layer "F.Cu")
		(hatch none 0.5)
		(connect_pads
			(clearance 0)
		)
		(min_thickness 0.25)
		(keepout
			(tracks allowed)
			(vias allowed)
			(pads allowed)
			(copperpour allowed)
			(footprints allowed)
		)
		(placement
			(enabled no)
			(sheetname "")
		)
		(fill
			(thermal_gap 0.5)
			(thermal_bridge_width 0.5)
			(island_removal_mode 0)
		)
		(polygon
			(pts
				(xy 413.275526 -293.05504) (xy 413.275526 -292.82644) (xy 415.307526 -292.82644) (xy 415.307526 -293.05504)
			)
		)
	)
	(zone
		(layer "F.Cu")
		(hatch none 0.5)
		(connect_pads
			(clearance 0)
		)
		(min_thickness 0.25)
		(keepout
			(tracks allowed)
			(vias allowed)
			(pads allowed)
			(copperpour allowed)
			(footprints allowed)
		)
		(placement
			(enabled no)
			(sheetname "")
		)
		(fill
			(thermal_gap 0.5)
			(thermal_bridge_width 0.5)
			(island_removal_mode 0)
		)
		(polygon
			(pts
				(xy 344.691462 -410.948886) (xy 344.691462 -406.105868) (xy 346.575888 -406.105868) (xy 346.575888 -410.948886)
			)
		)
	)
	(zone
		(layer "F.Cu")
		(hatch none 0.5)
		(connect_pads
			(clearance 0)
		)
		(min_thickness 0.25)
		(keepout
			(tracks allowed)
			(vias allowed)
			(pads allowed)
			(copperpour allowed)
			(footprints allowed)
		)
		(placement
			(enabled no)
			(sheetname "")
		)
		(fill
			(thermal_gap 0.5)
			(thermal_bridge_width 0.5)
			(island_removal_mode 0)
		)
		(polygon
			(pts
				(xy 440.006994 -284.556962) (xy 442.038994 -284.556962) (xy 442.038994 -284.328362) (xy 440.006994 -284.328362)
				(xy 439.875676 -284.328362) (xy 439.849768 -284.328362) (xy 439.849768 -284.556962) (xy 439.875676 -284.556962)
			)
		)
	)
	(zone
		(layer "F.Cu")
		(hatch none 0.5)
		(connect_pads
			(clearance 0)
		)
		(min_thickness 0.25)
		(keepout
			(tracks allowed)
			(vias allowed)
			(pads allowed)
			(copperpour allowed)
			(footprints allowed)
		)
		(placement
			(enabled no)
			(sheetname "")
		)
		(fill
			(thermal_gap 0.5)
			(thermal_bridge_width 0.5)
			(island_removal_mode 0)
		)
		(polygon
			(pts
				(xy 165.335458 -299.00499) (xy 165.335458 -298.77639) (xy 167.367458 -298.77639) (xy 167.367458 -299.00499)
			)
		)
	)
	(zone
		(layer "F.Cu")
		(hatch none 0.5)
		(connect_pads
			(clearance 0)
		)
		(min_thickness 0.25)
		(keepout
			(tracks allowed)
			(vias allowed)
			(pads allowed)
			(copperpour allowed)
			(footprints allowed)
		)
		(placement
			(enabled no)
			(sheetname "")
		)
		(fill
			(thermal_gap 0.5)
			(thermal_bridge_width 0.5)
			(island_removal_mode 0)
		)
		(polygon
			(pts
				(xy 207.154526 -309.826406) (xy 209.186526 -309.826406) (xy 209.186526 -310.055006) (xy 207.154526 -310.055006)
				(xy 207.018382 -310.055006) (xy 206.971392 -310.055006) (xy 206.971392 -309.826406) (xy 207.018382 -309.826406)
			)
		)
	)
	(zone
		(layer "F.Cu")
		(hatch none 0.5)
		(connect_pads
			(clearance 0)
		)
		(min_thickness 0.25)
		(keepout
			(tracks allowed)
			(vias allowed)
			(pads allowed)
			(copperpour allowed)
			(footprints allowed)
		)
		(placement
			(enabled no)
			(sheetname "")
		)
		(fill
			(thermal_gap 0.5)
			(thermal_bridge_width 0.5)
			(island_removal_mode 0)
		)
		(polygon
			(pts
				(xy 67.248532 -410.948886) (xy 67.248532 -406.105868) (xy 69.132958 -406.105868) (xy 69.132958 -410.948886)
			)
		)
	)
	(zone
		(layer "F.Cu")
		(hatch none 0.5)
		(connect_pads
			(clearance 0)
		)
		(min_thickness 0.25)
		(keepout
			(tracks allowed)
			(vias allowed)
			(pads allowed)
			(copperpour allowed)
			(footprints allowed)
		)
		(placement
			(enabled no)
			(sheetname "")
		)
		(fill
			(thermal_gap 0.5)
			(thermal_bridge_width 0.5)
			(island_removal_mode 0)
		)
		(polygon
			(pts
				(xy 62.147958 -237.066582) (xy 59.822842 -237.066582) (xy 59.69889 -237.066582) (xy 59.69889 -235.864908)
				(xy 62.404752 -235.864908) (xy 62.404752 -237.066582)
			)
		)
	)
	(zone
		(layer "F.Cu")
		(hatch none 0.5)
		(connect_pads
			(clearance 0)
		)
		(min_thickness 0.25)
		(keepout
			(tracks allowed)
			(vias allowed)
			(pads allowed)
			(copperpour allowed)
			(footprints allowed)
		)
		(placement
			(enabled no)
			(sheetname "")
		)
		(fill
			(thermal_gap 0.5)
			(thermal_bridge_width 0.5)
			(island_removal_mode 0)
		)
		(polygon
			(pts
				(xy 102.9335 -321.366388) (xy 102.9335 -319.154048) (xy 107.2642 -319.154048) (xy 107.2642 -321.366388)
			)
		)
	)
	(zone
		(layer "F.Cu")
		(hatch none 0.5)
		(connect_pads
			(clearance 0)
		)
		(min_thickness 0.25)
		(keepout
			(tracks allowed)
			(vias allowed)
			(pads allowed)
			(copperpour allowed)
			(footprints allowed)
		)
		(placement
			(enabled no)
			(sheetname "")
		)
		(fill
			(thermal_gap 0.5)
			(thermal_bridge_width 0.5)
			(island_removal_mode 0)
		)
		(polygon
			(pts
				(xy 41.29151 -303.366424) (xy 41.29151 -302.922686) (xy 43.616626 -302.922686) (xy 43.616626 -303.366424)
			)
		)
	)
	(zone
		(layer "F.Cu")
		(hatch none 0.5)
		(connect_pads
			(clearance 0)
		)
		(min_thickness 0.25)
		(keepout
			(tracks allowed)
			(vias allowed)
			(pads allowed)
			(copperpour allowed)
			(footprints allowed)
		)
		(placement
			(enabled no)
			(sheetname "")
		)
		(fill
			(thermal_gap 0.5)
			(thermal_bridge_width 0.5)
			(island_removal_mode 0)
		)
		(polygon
			(pts
				(xy 63.951612 -292.316662) (xy 63.951612 -291.872924) (xy 66.009012 -291.872924) (xy 66.009012 -292.316662)
			)
		)
	)
	(zone
		(layer "F.Cu")
		(hatch none 0.5)
		(connect_pads
			(clearance 0)
		)
		(min_thickness 0.25)
		(keepout
			(tracks allowed)
			(vias allowed)
			(pads allowed)
			(copperpour allowed)
			(footprints allowed)
		)
		(placement
			(enabled no)
			(sheetname "")
		)
		(fill
			(thermal_gap 0.5)
			(thermal_bridge_width 0.5)
			(island_removal_mode 0)
		)
		(polygon
			(pts
				(xy 337.65998 -359.575608) (xy 337.65998 -357.442008) (xy 342.392 -357.442008) (xy 342.392 -359.575608)
			)
		)
	)
	(zone
		(layer "F.Cu")
		(hatch none 0.5)
		(connect_pads
			(clearance 0)
		)
		(min_thickness 0.25)
		(keepout
			(tracks allowed)
			(vias allowed)
			(pads allowed)
			(copperpour allowed)
			(footprints allowed)
		)
		(placement
			(enabled no)
			(sheetname "")
		)
		(fill
			(thermal_gap 0.5)
			(thermal_bridge_width 0.5)
			(island_removal_mode 0)
		)
		(polygon
			(pts
				(xy 52.813966 -148.2217) (xy 54.145942 -148.2217) (xy 54.344824 -148.420582) (xy 54.344824 -150.212552)
				(xy 53.541676 -151.0157) (xy 51.063652 -151.0157) (xy 49.70399 -149.656038) (xy 49.70399 -144.164304)
				(xy 50.843688 -143.024606) (xy 54.764178 -143.024606) (xy 55.395622 -143.65605) (xy 55.395622 -145.372074)
				(xy 54.839108 -145.928588) (xy 52.690522 -145.928588) (xy 52.621942 -145.997168) (xy 52.621942 -148.029676)
			)
		)
	)
	(zone
		(layer "F.Cu")
		(hatch none 0.5)
		(connect_pads
			(clearance 0)
		)
		(min_thickness 0.25)
		(keepout
			(tracks allowed)
			(vias allowed)
			(pads allowed)
			(copperpour allowed)
			(footprints not_allowed)
		)
		(placement
			(enabled no)
			(sheetname "")
		)
		(fill
			(thermal_gap 0.5)
			(thermal_bridge_width 0.5)
			(island_removal_mode 0)
		)
		(polygon
			(pts
				(arc
					(start 453.799956 -435.600094)
					(mid 458.799946 -430.600104)
					(end 463.799936 -435.600094)
				)
				(arc
					(start 463.799936 -435.600094)
					(mid 458.799946 -440.600084)
					(end 453.799956 -435.600094)
				)
			)
		)
	)
	(zone
		(layer "F.Cu")
		(hatch none 0.5)
		(connect_pads
			(clearance 0)
		)
		(min_thickness 0.25)
		(keepout
			(tracks allowed)
			(vias allowed)
			(pads allowed)
			(copperpour allowed)
			(footprints not_allowed)
		)
		(placement
			(enabled no)
			(sheetname "")
		)
		(fill
			(thermal_gap 0.5)
			(thermal_bridge_width 0.5)
			(island_removal_mode 0)
		)
		(polygon
			(pts
				(xy 136.181338 -339.214968) (xy 136.181338 -314.770008) (xy 82.4484 -314.770008) (xy 82.4484 -339.214968)
				(xy 84.558632 -339.214968)
				(arc
					(start 84.558632 -334.724248)
					(mid 84.939385 -333.805029)
					(end 85.858604 -333.424276)
				)
				(xy 92.719144 -333.424276)
				(arc
					(start 92.719144 -331.314044)
					(mid 93.099897 -330.394825)
					(end 94.019116 -330.014072)
				)
				(arc
					(start 124.72162 -330.014072)
					(mid 125.640839 -330.394825)
					(end 126.021592 -331.314044)
				)
				(xy 126.021592 -333.424276)
				(arc
					(start 132.882132 -333.424276)
					(mid 133.801351 -333.805029)
					(end 134.182104 -334.724248)
				)
				(xy 134.182104 -339.214968)
			)
		)
	)
	(zone
		(layer "F.Cu")
		(hatch none 0.5)
		(connect_pads
			(clearance 0)
		)
		(min_thickness 0.25)
		(keepout
			(tracks allowed)
			(vias allowed)
			(pads allowed)
			(copperpour allowed)
			(footprints allowed)
		)
		(placement
			(enabled no)
			(sheetname "")
		)
		(fill
			(thermal_gap 0.5)
			(thermal_bridge_width 0.5)
			(island_removal_mode 0)
		)
		(polygon
			(pts
				(xy 41.29151 -200.51649) (xy 41.29151 -200.072752) (xy 43.616626 -200.072752) (xy 43.616626 -200.51649)
			)
		)
	)
	(zone
		(layer "F.Cu")
		(hatch none 0.5)
		(connect_pads
			(clearance 0)
		)
		(min_thickness 0.25)
		(keepout
			(tracks allowed)
			(vias allowed)
			(pads allowed)
			(copperpour allowed)
			(footprints allowed)
		)
		(placement
			(enabled no)
			(sheetname "")
		)
		(fill
			(thermal_gap 0.5)
			(thermal_bridge_width 0.5)
			(island_removal_mode 0)
		)
		(polygon
			(pts
				(xy 198.50354 -404.3807) (xy 198.50354 -401.08124) (xy 201.83602 -401.08124) (xy 201.83602 -404.3807)
			)
		)
	)
	(zone
		(layer "F.Cu")
		(hatch none 0.5)
		(connect_pads
			(clearance 0)
		)
		(min_thickness 0.25)
		(keepout
			(tracks not_allowed)
			(vias allowed)
			(pads allowed)
			(copperpour not_allowed)
			(footprints allowed)
		)
		(placement
			(enabled no)
			(sheetname "")
		)
		(fill
			(thermal_gap 0.5)
			(thermal_bridge_width 0.5)
			(island_removal_mode 0)
		)
		(polygon
			(pts
				(xy 242.149884 -41.924986) (xy 242.149884 -36.924996) (xy 237.949994 -36.924996) (xy 237.949994 -41.924986)
			)
		)
	)
	(zone
		(layer "F.Cu")
		(hatch none 0.5)
		(connect_pads
			(clearance 0)
		)
		(min_thickness 0.25)
		(keepout
			(tracks allowed)
			(vias allowed)
			(pads allowed)
			(copperpour allowed)
			(footprints allowed)
		)
		(placement
			(enabled no)
			(sheetname "")
		)
		(fill
			(thermal_gap 0.5)
			(thermal_bridge_width 0.5)
			(island_removal_mode 0)
		)
		(polygon
			(pts
				(xy 207.154526 -223.976438) (xy 209.186526 -223.976438) (xy 209.186526 -224.205038) (xy 207.154526 -224.205038)
				(xy 207.018382 -224.205038) (xy 206.971392 -224.205038) (xy 206.971392 -223.976438) (xy 207.018382 -223.976438)
			)
		)
	)
	(zone
		(layer "F.Cu")
		(hatch none 0.5)
		(connect_pads
			(clearance 0)
		)
		(min_thickness 0.25)
		(keepout
			(tracks allowed)
			(vias allowed)
			(pads allowed)
			(copperpour allowed)
			(footprints allowed)
		)
		(placement
			(enabled no)
			(sheetname "")
		)
		(fill
			(thermal_gap 0.5)
			(thermal_bridge_width 0.5)
			(island_removal_mode 0)
		)
		(polygon
			(pts
				(xy 424.919394 -197.626478) (xy 426.951394 -197.626478) (xy 426.951394 -197.855078) (xy 424.919394 -197.855078)
				(xy 424.78325 -197.855078) (xy 424.73626 -197.855078) (xy 424.73626 -197.626478) (xy 424.78325 -197.626478)
			)
		)
	)
	(zone
		(layer "F.Cu")
		(hatch none 0.5)
		(connect_pads
			(clearance 0)
		)
		(min_thickness 0.25)
		(keepout
			(tracks allowed)
			(vias allowed)
			(pads allowed)
			(copperpour allowed)
			(footprints allowed)
		)
		(placement
			(enabled no)
			(sheetname "")
		)
		(fill
			(thermal_gap 0.5)
			(thermal_bridge_width 0.5)
			(island_removal_mode 0)
		)
		(polygon
			(pts
				(xy 277.58771 -280.416508) (xy 277.58771 -279.97277) (xy 279.912826 -279.97277) (xy 279.912826 -280.416508)
			)
		)
	)
	(zone
		(layer "F.Cu")
		(hatch none 0.5)
		(connect_pads
			(clearance 0)
		)
		(min_thickness 0.25)
		(keepout
			(tracks allowed)
			(vias allowed)
			(pads allowed)
			(copperpour allowed)
			(footprints allowed)
		)
		(placement
			(enabled no)
			(sheetname "")
		)
		(fill
			(thermal_gap 0.5)
			(thermal_bridge_width 0.5)
			(island_removal_mode 0)
		)
		(polygon
			(pts
				(xy 165.335458 -216.554812) (xy 165.335458 -216.326212) (xy 167.367458 -216.326212) (xy 167.367458 -216.554812)
			)
		)
	)
	(zone
		(layer "F.Cu")
		(hatch none 0.5)
		(connect_pads
			(clearance 0)
		)
		(min_thickness 0.25)
		(keepout
			(tracks allowed)
			(vias allowed)
			(pads allowed)
			(copperpour allowed)
			(footprints not_allowed)
		)
		(placement
			(enabled no)
			(sheetname "")
		)
		(fill
			(thermal_gap 0.5)
			(thermal_bridge_width 0.5)
			(island_removal_mode 0)
		)
		(polygon
			(pts
				(xy 7.13994 -339.092032) (xy 66.047112 -339.092032) (xy 66.047112 -331.092048) (xy 7.13994 -331.092048)
			)
		)
	)
	(zone
		(layer "F.Cu")
		(hatch none 0.5)
		(connect_pads
			(clearance 0)
		)
		(min_thickness 0.25)
		(keepout
			(tracks allowed)
			(vias allowed)
			(pads allowed)
			(copperpour allowed)
			(footprints allowed)
		)
		(placement
			(enabled no)
			(sheetname "")
		)
		(fill
			(thermal_gap 0.5)
			(thermal_bridge_width 0.5)
			(island_removal_mode 0)
		)
		(polygon
			(pts
				(xy 157.791658 -214.85479) (xy 157.791658 -214.62619) (xy 159.823658 -214.62619) (xy 159.823658 -214.85479)
			)
		)
	)
	(zone
		(layer "F.Cu")
		(hatch none 0.5)
		(connect_pads
			(clearance 0)
		)
		(min_thickness 0.25)
		(keepout
			(tracks allowed)
			(vias allowed)
			(pads allowed)
			(copperpour allowed)
			(footprints allowed)
		)
		(placement
			(enabled no)
			(sheetname "")
		)
		(fill
			(thermal_gap 0.5)
			(thermal_bridge_width 0.5)
			(island_removal_mode 0)
		)
		(polygon
			(pts
				(xy 304.319178 -291.466524) (xy 304.319178 -291.022786) (xy 306.644294 -291.022786) (xy 306.644294 -291.466524)
			)
		)
	)
	(zone
		(layer "F.Cu")
		(hatch none 0.5)
		(connect_pads
			(clearance 0)
		)
		(min_thickness 0.25)
		(keepout
			(tracks allowed)
			(vias allowed)
			(pads allowed)
			(copperpour allowed)
			(footprints allowed)
		)
		(placement
			(enabled no)
			(sheetname "")
		)
		(fill
			(thermal_gap 0.5)
			(thermal_bridge_width 0.5)
			(island_removal_mode 0)
		)
		(polygon
			(pts
				(xy 56.37911 -261.71652) (xy 56.37911 -261.272782) (xy 58.704226 -261.272782) (xy 58.704226 -261.71652)
			)
		)
	)
	(zone
		(layer "F.Cu")
		(hatch none 0.5)
		(connect_pads
			(clearance 0)
		)
		(min_thickness 0.25)
		(keepout
			(tracks allowed)
			(vias allowed)
			(pads allowed)
			(copperpour allowed)
			(footprints allowed)
		)
		(placement
			(enabled no)
			(sheetname "")
		)
		(fill
			(thermal_gap 0.5)
			(thermal_bridge_width 0.5)
			(island_removal_mode 0)
		)
		(polygon
			(pts
				(xy 304.319178 -205.616556) (xy 304.319178 -205.172818) (xy 306.644294 -205.172818) (xy 306.644294 -205.616556)
			)
		)
	)
	(zone
		(layer "F.Cu")
		(hatch none 0.5)
		(connect_pads
			(clearance 0)
		)
		(min_thickness 0.25)
		(keepout
			(tracks allowed)
			(vias allowed)
			(pads allowed)
			(copperpour allowed)
			(footprints allowed)
		)
		(placement
			(enabled no)
			(sheetname "")
		)
		(fill
			(thermal_gap 0.5)
			(thermal_bridge_width 0.5)
			(island_removal_mode 0)
		)
		(polygon
			(pts
				(xy 234.1245 -251.831348) (xy 234.1245 -249.431048) (xy 236.57814 -249.431048) (xy 236.57814 -251.831348)
			)
		)
	)
	(zone
		(layer "F.Cu")
		(hatch none 0.5)
		(connect_pads
			(clearance 0)
		)
		(min_thickness 0.25)
		(keepout
			(tracks allowed)
			(vias allowed)
			(pads allowed)
			(copperpour allowed)
			(footprints allowed)
		)
		(placement
			(enabled no)
			(sheetname "")
		)
		(fill
			(thermal_gap 0.5)
			(thermal_bridge_width 0.5)
			(island_removal_mode 0)
		)
		(polygon
			(pts
				(xy 17.6657 -12.758928) (xy 17.6657 -10.099548) (xy 33.67278 -10.099548) (xy 33.67278 -12.758928)
			)
		)
	)
	(zone
		(layer "F.Cu")
		(hatch none 0.5)
		(connect_pads
			(clearance 0)
		)
		(min_thickness 0.25)
		(keepout
			(tracks allowed)
			(vias allowed)
			(pads allowed)
			(copperpour allowed)
			(footprints allowed)
		)
		(placement
			(enabled no)
			(sheetname "")
		)
		(fill
			(thermal_gap 0.5)
			(thermal_bridge_width 0.5)
			(island_removal_mode 0)
		)
		(polygon
			(pts
				(xy 455.094594 -313.226196) (xy 457.126594 -313.226196) (xy 457.126594 -313.454796) (xy 455.094594 -313.454796)
				(xy 454.963276 -313.454796) (xy 454.937368 -313.454796) (xy 454.937368 -313.226196) (xy 454.963276 -313.226196)
			)
		)
	)
	(zone
		(layer "F.Cu")
		(hatch none 0.5)
		(connect_pads
			(clearance 0)
		)
		(min_thickness 0.25)
		(keepout
			(tracks allowed)
			(vias allowed)
			(pads allowed)
			(copperpour allowed)
			(footprints allowed)
		)
		(placement
			(enabled no)
			(sheetname "")
		)
		(fill
			(thermal_gap 0.5)
			(thermal_bridge_width 0.5)
			(island_removal_mode 0)
		)
		(polygon
			(pts
				(xy 292.67531 -237.066582) (xy 292.67531 -236.622844) (xy 295.000426 -236.622844) (xy 295.000426 -237.066582)
			)
		)
	)
	(zone
		(layer "F.Cu")
		(hatch none 0.5)
		(connect_pads
			(clearance 0)
		)
		(min_thickness 0.25)
		(keepout
			(tracks allowed)
			(vias allowed)
			(pads allowed)
			(copperpour allowed)
			(footprints allowed)
		)
		(placement
			(enabled no)
			(sheetname "")
		)
		(fill
			(thermal_gap 0.5)
			(thermal_bridge_width 0.5)
			(island_removal_mode 0)
		)
		(polygon
			(pts
				(xy 178.08448 -358.978708) (xy 178.08448 -356.032308) (xy 184.65038 -356.032308) (xy 184.65038 -358.978708)
			)
		)
	)
	(zone
		(layer "F.Cu")
		(hatch none 0.5)
		(connect_pads
			(clearance 0)
		)
		(min_thickness 0.25)
		(keepout
			(tracks allowed)
			(vias allowed)
			(pads allowed)
			(copperpour allowed)
			(footprints allowed)
		)
		(placement
			(enabled no)
			(sheetname "")
		)
		(fill
			(thermal_gap 0.5)
			(thermal_bridge_width 0.5)
			(island_removal_mode 0)
		)
		(polygon
			(pts
				(xy 43.270678 -18.570702) (xy 43.270678 -15.436088) (xy 45.04944 -15.436088) (xy 45.04944 -18.570702)
			)
		)
	)
	(zone
		(layer "F.Cu")
		(hatch none 0.5)
		(connect_pads
			(clearance 0)
		)
		(min_thickness 0.25)
		(keepout
			(tracks allowed)
			(vias allowed)
			(pads allowed)
			(copperpour allowed)
			(footprints allowed)
		)
		(placement
			(enabled no)
			(sheetname "")
		)
		(fill
			(thermal_gap 0.5)
			(thermal_bridge_width 0.5)
			(island_removal_mode 0)
		)
		(polygon
			(pts
				(xy 415.307526 -233.555032) (xy 413.275526 -233.555032) (xy 413.072072 -233.555032) (xy 413.072072 -232.782872)
				(xy 415.528506 -232.782872) (xy 415.528506 -233.555032)
			)
		)
	)
	(zone
		(layer "F.Cu")
		(hatch none 0.5)
		(connect_pads
			(clearance 0)
		)
		(min_thickness 0.25)
		(keepout
			(tracks allowed)
			(vias allowed)
			(pads allowed)
			(copperpour allowed)
			(footprints allowed)
		)
		(placement
			(enabled no)
			(sheetname "")
		)
		(fill
			(thermal_gap 0.5)
			(thermal_bridge_width 0.5)
			(island_removal_mode 0)
		)
		(polygon
			(pts
				(xy 311.91708 -249.81662) (xy 311.91708 -249.372882) (xy 314.12688 -249.372882) (xy 314.12688 -249.81662)
			)
		)
	)
	(zone
		(layer "F.Cu")
		(hatch none 0.5)
		(connect_pads
			(clearance 0)
		)
		(min_thickness 0.25)
		(keepout
			(tracks allowed)
			(vias allowed)
			(pads allowed)
			(copperpour allowed)
			(footprints allowed)
		)
		(placement
			(enabled no)
			(sheetname "")
		)
		(fill
			(thermal_gap 0.5)
			(thermal_bridge_width 0.5)
			(island_removal_mode 0)
		)
		(polygon
			(pts
				(xy 262.50011 -299.116496) (xy 262.50011 -298.672758) (xy 264.825226 -298.672758) (xy 264.825226 -299.116496)
			)
		)
	)
	(zone
		(layer "F.Cu")
		(hatch none 0.5)
		(connect_pads
			(clearance 0)
		)
		(min_thickness 0.25)
		(keepout
			(tracks allowed)
			(vias allowed)
			(pads allowed)
			(copperpour allowed)
			(footprints allowed)
		)
		(placement
			(enabled no)
			(sheetname "")
		)
		(fill
			(thermal_gap 0.5)
			(thermal_bridge_width 0.5)
			(island_removal_mode 0)
		)
		(polygon
			(pts
				(xy 161.891726 -209.754978) (xy 161.891726 -209.526378) (xy 163.923726 -209.526378) (xy 163.923726 -209.754978)
			)
		)
	)
	(zone
		(layer "F.Cu")
		(hatch none 0.5)
		(connect_pads
			(clearance 0)
		)
		(min_thickness 0.25)
		(keepout
			(tracks allowed)
			(vias allowed)
			(pads allowed)
			(copperpour allowed)
			(footprints allowed)
		)
		(placement
			(enabled no)
			(sheetname "")
		)
		(fill
			(thermal_gap 0.5)
			(thermal_bridge_width 0.5)
			(island_removal_mode 0)
		)
		(polygon
			(pts
				(xy 207.154526 -211.2264) (xy 209.186526 -211.2264) (xy 209.186526 -211.455) (xy 207.154526 -211.455)
				(xy 207.018382 -211.455) (xy 206.971392 -211.455) (xy 206.971392 -211.2264) (xy 207.018382 -211.2264)
			)
		)
	)
	(zone
		(layer "F.Cu")
		(hatch none 0.5)
		(connect_pads
			(clearance 0)
		)
		(min_thickness 0.25)
		(keepout
			(tracks allowed)
			(vias allowed)
			(pads allowed)
			(copperpour allowed)
			(footprints allowed)
		)
		(placement
			(enabled no)
			(sheetname "")
		)
		(fill
			(thermal_gap 0.5)
			(thermal_bridge_width 0.5)
			(island_removal_mode 0)
		)
		(polygon
			(pts
				(xy 409.831794 -298.77639) (xy 411.863794 -298.77639) (xy 411.863794 -299.00499) (xy 409.831794 -299.00499)
				(xy 409.69565 -299.00499) (xy 409.64866 -299.00499) (xy 409.64866 -298.77639) (xy 409.69565 -298.77639)
			)
		)
	)
	(zone
		(layer "F.Cu")
		(hatch none 0.5)
		(connect_pads
			(clearance 0)
		)
		(min_thickness 0.25)
		(keepout
			(tracks allowed)
			(vias allowed)
			(pads allowed)
			(copperpour allowed)
			(footprints allowed)
		)
		(placement
			(enabled no)
			(sheetname "")
		)
		(fill
			(thermal_gap 0.5)
			(thermal_bridge_width 0.5)
			(island_removal_mode 0)
		)
		(polygon
			(pts
				(xy 455.094594 -237.806992) (xy 457.126594 -237.806992) (xy 457.126594 -237.578392) (xy 455.094594 -237.578392)
				(xy 454.963276 -237.578392) (xy 454.937368 -237.578392) (xy 454.937368 -237.806992) (xy 454.963276 -237.806992)
			)
		)
	)
	(zone
		(layer "F.Cu")
		(hatch none 0.5)
		(connect_pads
			(clearance 0)
		)
		(min_thickness 0.25)
		(keepout
			(tracks allowed)
			(vias allowed)
			(pads allowed)
			(copperpour allowed)
			(footprints allowed)
		)
		(placement
			(enabled no)
			(sheetname "")
		)
		(fill
			(thermal_gap 0.5)
			(thermal_bridge_width 0.5)
			(island_removal_mode 0)
		)
		(polygon
			(pts
				(xy 394.63218 -5.888228) (xy 394.63218 -3.952748) (xy 396.80388 -3.952748) (xy 396.80388 -5.888228)
			)
		)
	)
	(zone
		(layer "F.Cu")
		(hatch none 0.5)
		(connect_pads
			(clearance 0)
		)
		(min_thickness 0.25)
		(keepout
			(tracks allowed)
			(vias allowed)
			(pads allowed)
			(copperpour allowed)
			(footprints allowed)
		)
		(placement
			(enabled no)
			(sheetname "")
		)
		(fill
			(thermal_gap 0.5)
			(thermal_bridge_width 0.5)
			(island_removal_mode 0)
		)
		(polygon
			(pts
				(xy 307.76291 -227.716588) (xy 307.76291 -227.27285) (xy 310.088026 -227.27285) (xy 310.088026 -227.716588)
			)
		)
	)
	(zone
		(layer "F.Cu")
		(hatch none 0.5)
		(connect_pads
			(clearance 0)
		)
		(min_thickness 0.25)
		(keepout
			(tracks allowed)
			(vias allowed)
			(pads allowed)
			(copperpour allowed)
			(footprints allowed)
		)
		(placement
			(enabled no)
			(sheetname "")
		)
		(fill
			(thermal_gap 0.5)
			(thermal_bridge_width 0.5)
			(island_removal_mode 0)
		)
		(polygon
			(pts
				(xy 59.822842 -211.566506) (xy 59.822842 -211.122768) (xy 62.147958 -211.122768) (xy 62.147958 -211.566506)
			)
		)
	)
	(zone
		(layer "F.Cu")
		(hatch none 0.5)
		(connect_pads
			(clearance 0)
		)
		(min_thickness 0.25)
		(keepout
			(tracks allowed)
			(vias allowed)
			(pads allowed)
			(copperpour allowed)
			(footprints allowed)
		)
		(placement
			(enabled no)
			(sheetname "")
		)
		(fill
			(thermal_gap 0.5)
			(thermal_bridge_width 0.5)
			(island_removal_mode 0)
		)
		(polygon
			(pts
				(xy 14.560042 -197.116446) (xy 14.560042 -196.672708) (xy 16.885158 -196.672708) (xy 16.885158 -197.116446)
			)
		)
	)
	(zone
		(layer "F.Cu")
		(hatch none 0.5)
		(connect_pads
			(clearance 0)
		)
		(min_thickness 0.25)
		(keepout
			(tracks allowed)
			(vias allowed)
			(pads allowed)
			(copperpour allowed)
			(footprints allowed)
		)
		(placement
			(enabled no)
			(sheetname "")
		)
		(fill
			(thermal_gap 0.5)
			(thermal_bridge_width 0.5)
			(island_removal_mode 0)
		)
		(polygon
			(pts
				(xy 304.869342 -410.948886) (xy 304.869342 -406.105868) (xy 306.753768 -406.105868) (xy 306.753768 -410.948886)
			)
		)
	)
	(zone
		(layer "F.Cu")
		(hatch none 0.5)
		(connect_pads
			(clearance 0)
		)
		(min_thickness 0.25)
		(keepout
			(tracks allowed)
			(vias allowed)
			(pads allowed)
			(copperpour allowed)
			(footprints allowed)
		)
		(placement
			(enabled no)
			(sheetname "")
		)
		(fill
			(thermal_gap 0.5)
			(thermal_bridge_width 0.5)
			(island_removal_mode 0)
		)
		(polygon
			(pts
				(xy 93.545406 -333.45755) (xy 94.883986 -333.45755) (xy 95.277686 -333.85125) (xy 95.277686 -336.06613)
				(xy 95.468186 -336.25663) (xy 99.014026 -336.25663) (xy 99.229926 -336.47253) (xy 99.229926 -338.63407)
				(xy 99.229926 -338.835492) (xy 99.113086 -338.952332) (xy 93.560646 -338.952332) (xy 93.189806 -338.581492)
				(xy 93.189806 -338.34959) (xy 93.189806 -333.81315)
			)
		)
	)
	(zone
		(layer "F.Cu")
		(hatch none 0.5)
		(connect_pads
			(clearance 0)
		)
		(min_thickness 0.25)
		(keepout
			(tracks allowed)
			(vias allowed)
			(pads allowed)
			(copperpour allowed)
			(footprints allowed)
		)
		(placement
			(enabled no)
			(sheetname "")
		)
		(fill
			(thermal_gap 0.5)
			(thermal_bridge_width 0.5)
			(island_removal_mode 0)
		)
		(polygon
			(pts
				(xy 444.77432 -73.843388) (xy 444.77432 -77.089508) (xy 446.26276 -78.577948) (xy 451.39356 -78.577948)
				(xy 453.75068 -76.220828) (xy 453.75068 -74.348848) (xy 452.53656 -73.134728) (xy 445.48298 -73.134728)
			)
		)
	)
	(zone
		(layer "F.Cu")
		(hatch none 0.5)
		(connect_pads
			(clearance 0)
		)
		(min_thickness 0.25)
		(keepout
			(tracks allowed)
			(vias allowed)
			(pads allowed)
			(copperpour allowed)
			(footprints allowed)
		)
		(placement
			(enabled no)
			(sheetname "")
		)
		(fill
			(thermal_gap 0.5)
			(thermal_bridge_width 0.5)
			(island_removal_mode 0)
		)
		(polygon
			(pts
				(xy 310.088026 -274.466558) (xy 307.76291 -274.466558) (xy 307.431186 -274.466558) (xy 307.431186 -273.216116)
				(xy 310.346598 -273.216116) (xy 310.346598 -274.466558)
			)
		)
	)
	(zone
		(layer "F.Cu")
		(hatch none 0.5)
		(connect_pads
			(clearance 0)
		)
		(min_thickness 0.25)
		(keepout
			(tracks allowed)
			(vias allowed)
			(pads allowed)
			(copperpour allowed)
			(footprints allowed)
		)
		(placement
			(enabled no)
			(sheetname "")
		)
		(fill
			(thermal_gap 0.5)
			(thermal_bridge_width 0.5)
			(island_removal_mode 0)
		)
		(polygon
			(pts
				(xy 176.979326 -293.906956) (xy 179.011326 -293.906956) (xy 179.011326 -293.678356) (xy 176.979326 -293.678356)
				(xy 176.848008 -293.678356) (xy 176.8221 -293.678356) (xy 176.8221 -293.906956) (xy 176.848008 -293.906956)
			)
		)
	)
	(zone
		(layer "F.Cu")
		(hatch none 0.5)
		(connect_pads
			(clearance 0)
		)
		(min_thickness 0.25)
		(keepout
			(tracks allowed)
			(vias allowed)
			(pads allowed)
			(copperpour allowed)
			(footprints allowed)
		)
		(placement
			(enabled no)
			(sheetname "")
		)
		(fill
			(thermal_gap 0.5)
			(thermal_bridge_width 0.5)
			(island_removal_mode 0)
		)
		(polygon
			(pts
				(xy 443.450726 -265.854942) (xy 443.450726 -265.626342) (xy 445.482726 -265.626342) (xy 445.482726 -265.854942)
			)
		)
	)
	(zone
		(layer "F.Cu")
		(hatch none 0.5)
		(connect_pads
			(clearance 0)
		)
		(min_thickness 0.25)
		(keepout
			(tracks allowed)
			(vias allowed)
			(pads allowed)
			(copperpour allowed)
			(footprints allowed)
		)
		(placement
			(enabled no)
			(sheetname "")
		)
		(fill
			(thermal_gap 0.5)
			(thermal_bridge_width 0.5)
			(island_removal_mode 0)
		)
		(polygon
			(pts
				(xy 192.066926 -209.75701) (xy 194.098926 -209.75701) (xy 194.098926 -209.52841) (xy 192.066926 -209.52841)
				(xy 191.935608 -209.52841) (xy 191.9097 -209.52841) (xy 191.9097 -209.75701) (xy 191.935608 -209.75701)
			)
		)
	)
	(zone
		(layer "F.Cu")
		(hatch none 0.5)
		(connect_pads
			(clearance 0)
		)
		(min_thickness 0.25)
		(keepout
			(tracks allowed)
			(vias allowed)
			(pads allowed)
			(copperpour allowed)
			(footprints allowed)
		)
		(placement
			(enabled no)
			(sheetname "")
		)
		(fill
			(thermal_gap 0.5)
			(thermal_bridge_width 0.5)
			(island_removal_mode 0)
		)
		(polygon
			(pts
				(xy 274.143978 -280.416508) (xy 274.143978 -279.97277) (xy 276.469094 -279.97277) (xy 276.469094 -280.416508)
			)
		)
	)
	(zone
		(layer "F.Cu")
		(hatch none 0.5)
		(connect_pads
			(clearance 0)
		)
		(min_thickness 0.25)
		(keepout
			(tracks allowed)
			(vias allowed)
			(pads allowed)
			(copperpour allowed)
			(footprints allowed)
		)
		(placement
			(enabled no)
			(sheetname "")
		)
		(fill
			(thermal_gap 0.5)
			(thermal_bridge_width 0.5)
			(island_removal_mode 0)
		)
		(polygon
			(pts
				(xy 455.094594 -219.107004) (xy 457.126594 -219.107004) (xy 457.126594 -218.878404) (xy 455.094594 -218.878404)
				(xy 454.963276 -218.878404) (xy 454.937368 -218.878404) (xy 454.937368 -219.107004) (xy 454.963276 -219.107004)
			)
		)
	)
	(zone
		(layer "F.Cu")
		(hatch none 0.5)
		(connect_pads
			(clearance 0)
		)
		(min_thickness 0.25)
		(keepout
			(tracks allowed)
			(vias allowed)
			(pads allowed)
			(copperpour allowed)
			(footprints allowed)
		)
		(placement
			(enabled no)
			(sheetname "")
		)
		(fill
			(thermal_gap 0.5)
			(thermal_bridge_width 0.5)
			(island_removal_mode 0)
		)
		(polygon
			(pts
				(xy 314.059062 -410.948886) (xy 314.059062 -406.105868) (xy 315.943488 -406.105868) (xy 315.943488 -410.948886)
			)
		)
	)
	(zone
		(layer "F.Cu")
		(hatch none 0.5)
		(connect_pads
			(clearance 0)
		)
		(min_thickness 0.25)
		(keepout
			(tracks allowed)
			(vias allowed)
			(pads allowed)
			(copperpour allowed)
			(footprints allowed)
		)
		(placement
			(enabled no)
			(sheetname "")
		)
		(fill
			(thermal_gap 0.5)
			(thermal_bridge_width 0.5)
			(island_removal_mode 0)
		)
		(polygon
			(pts
				(xy 409.831794 -285.404814) (xy 409.831794 -285.176214) (xy 411.863794 -285.176214) (xy 411.863794 -285.404814)
			)
		)
	)
	(zone
		(layer "F.Cu")
		(hatch none 0.5)
		(connect_pads
			(clearance 0)
		)
		(min_thickness 0.25)
		(keepout
			(tracks allowed)
			(vias allowed)
			(pads allowed)
			(copperpour allowed)
			(footprints allowed)
		)
		(placement
			(enabled no)
			(sheetname "")
		)
		(fill
			(thermal_gap 0.5)
			(thermal_bridge_width 0.5)
			(island_removal_mode 0)
		)
		(polygon
			(pts
				(xy 29.647642 -314.41644) (xy 29.647642 -313.972702) (xy 31.972758 -313.972702) (xy 31.972758 -314.41644)
			)
		)
	)
	(zone
		(layer "F.Cu")
		(hatch none 0.5)
		(connect_pads
			(clearance 0)
		)
		(min_thickness 0.25)
		(keepout
			(tracks allowed)
			(vias allowed)
			(pads allowed)
			(copperpour allowed)
			(footprints allowed)
		)
		(placement
			(enabled no)
			(sheetname "")
		)
		(fill
			(thermal_gap 0.5)
			(thermal_bridge_width 0.5)
			(island_removal_mode 0)
		)
		(polygon
			(pts
				(xy 262.50011 -221.766638) (xy 262.50011 -221.3229) (xy 264.825226 -221.3229) (xy 264.825226 -221.766638)
			)
		)
	)
	(zone
		(layer "F.Cu")
		(hatch none 0.5)
		(connect_pads
			(clearance 0)
		)
		(min_thickness 0.25)
		(keepout
			(tracks allowed)
			(vias allowed)
			(pads allowed)
			(copperpour allowed)
			(footprints allowed)
		)
		(placement
			(enabled no)
			(sheetname "")
		)
		(fill
			(thermal_gap 0.5)
			(thermal_bridge_width 0.5)
			(island_removal_mode 0)
		)
		(polygon
			(pts
				(xy 277.58771 -231.116632) (xy 277.58771 -230.672894) (xy 279.912826 -230.672894) (xy 279.912826 -231.116632)
			)
		)
	)
	(zone
		(layer "F.Cu")
		(hatch none 0.5)
		(connect_pads
			(clearance 0)
		)
		(min_thickness 0.25)
		(keepout
			(tracks allowed)
			(vias allowed)
			(pads allowed)
			(copperpour allowed)
			(footprints allowed)
		)
		(placement
			(enabled no)
			(sheetname "")
		)
		(fill
			(thermal_gap 0.5)
			(thermal_bridge_width 0.5)
			(island_removal_mode 0)
		)
		(polygon
			(pts
				(xy 56.37911 -224.316544) (xy 56.37911 -223.872806) (xy 58.704226 -223.872806) (xy 58.704226 -224.316544)
			)
		)
	)
	(zone
		(layer "F.Cu")
		(hatch none 0.5)
		(connect_pads
			(clearance 0)
		)
		(min_thickness 0.25)
		(keepout
			(tracks not_allowed)
			(vias allowed)
			(pads allowed)
			(copperpour not_allowed)
			(footprints allowed)
		)
		(placement
			(enabled no)
			(sheetname "")
		)
		(fill
			(thermal_gap 0.5)
			(thermal_bridge_width 0.5)
			(island_removal_mode 0)
		)
		(polygon
			(pts
				(arc
					(start 260.649974 -22.29993)
					(mid 265.649964 -17.29994)
					(end 270.649954 -22.29993)
				)
				(arc
					(start 270.649954 -22.29993)
					(mid 265.649964 -27.29992)
					(end 260.649974 -22.29993)
				)
			)
		)
	)
	(zone
		(layer "F.Cu")
		(hatch none 0.5)
		(connect_pads
			(clearance 0)
		)
		(min_thickness 0.25)
		(keepout
			(tracks allowed)
			(vias allowed)
			(pads allowed)
			(copperpour allowed)
			(footprints allowed)
		)
		(placement
			(enabled no)
			(sheetname "")
		)
		(fill
			(thermal_gap 0.5)
			(thermal_bridge_width 0.5)
			(island_removal_mode 0)
		)
		(polygon
			(pts
				(xy 180.423058 -230.154988) (xy 180.423058 -229.926388) (xy 182.455058 -229.926388) (xy 182.455058 -230.154988)
			)
		)
	)
	(zone
		(layer "F.Cu")
		(hatch none 0.5)
		(connect_pads
			(clearance 0)
		)
		(min_thickness 0.25)
		(keepout
			(tracks allowed)
			(vias allowed)
			(pads allowed)
			(copperpour allowed)
			(footprints allowed)
		)
		(placement
			(enabled no)
			(sheetname "")
		)
		(fill
			(thermal_gap 0.5)
			(thermal_bridge_width 0.5)
			(island_removal_mode 0)
		)
		(polygon
			(pts
				(xy 11.11631 -196.266562) (xy 11.11631 -195.822824) (xy 13.441426 -195.822824) (xy 13.441426 -196.266562)
			)
		)
	)
	(zone
		(layer "F.Cu")
		(hatch none 0.5)
		(connect_pads
			(clearance 0)
		)
		(min_thickness 0.25)
		(keepout
			(tracks allowed)
			(vias allowed)
			(pads allowed)
			(copperpour allowed)
			(footprints allowed)
		)
		(placement
			(enabled no)
			(sheetname "")
		)
		(fill
			(thermal_gap 0.5)
			(thermal_bridge_width 0.5)
			(island_removal_mode 0)
		)
		(polygon
			(pts
				(xy 409.831794 -240.976404) (xy 411.863794 -240.976404) (xy 411.978602 -240.976404) (xy 411.978602 -241.678968)
				(xy 409.625038 -241.678968) (xy 409.625038 -240.976404)
			)
		)
	)
	(zone
		(layer "F.Cu")
		(hatch none 0.5)
		(connect_pads
			(clearance 0)
		)
		(min_thickness 0.25)
		(keepout
			(tracks allowed)
			(vias allowed)
			(pads allowed)
			(copperpour allowed)
			(footprints allowed)
		)
		(placement
			(enabled no)
			(sheetname "")
		)
		(fill
			(thermal_gap 0.5)
			(thermal_bridge_width 0.5)
			(island_removal_mode 0)
		)
		(polygon
			(pts
				(xy 413.982916 -164.718746) (xy 417.988496 -164.718746) (xy 418.468556 -164.238686) (xy 418.468556 -162.173666)
				(xy 418.196776 -161.901886) (xy 416.342576 -161.901886) (xy 416.091116 -161.650426) (xy 416.091116 -159.730186)
				(xy 415.674556 -159.313626) (xy 414.183576 -159.313626) (xy 413.535876 -159.961326) (xy 413.535876 -164.271706)
			)
		)
	)
	(zone
		(layer "F.Cu")
		(hatch none 0.5)
		(connect_pads
			(clearance 0)
		)
		(min_thickness 0.25)
		(keepout
			(tracks allowed)
			(vias allowed)
			(pads allowed)
			(copperpour allowed)
			(footprints allowed)
		)
		(placement
			(enabled no)
			(sheetname "")
		)
		(fill
			(thermal_gap 0.5)
			(thermal_bridge_width 0.5)
			(island_removal_mode 0)
		)
		(polygon
			(pts
				(xy 304.319178 -294.866568) (xy 304.319178 -294.42283) (xy 306.644294 -294.42283) (xy 306.644294 -294.866568)
			)
		)
	)
	(zone
		(layer "F.Cu")
		(hatch none 0.5)
		(connect_pads
			(clearance 0)
		)
		(min_thickness 0.25)
		(keepout
			(tracks allowed)
			(vias allowed)
			(pads allowed)
			(copperpour allowed)
			(footprints allowed)
		)
		(placement
			(enabled no)
			(sheetname "")
		)
		(fill
			(thermal_gap 0.5)
			(thermal_bridge_width 0.5)
			(island_removal_mode 0)
		)
		(polygon
			(pts
				(xy 262.50011 -248.966482) (xy 262.50011 -248.522744) (xy 264.825226 -248.522744) (xy 264.825226 -248.966482)
			)
		)
	)
	(zone
		(layer "F.Cu")
		(hatch none 0.5)
		(connect_pads
			(clearance 0)
		)
		(min_thickness 0.25)
		(keepout
			(tracks allowed)
			(vias allowed)
			(pads allowed)
			(copperpour allowed)
			(footprints allowed)
		)
		(placement
			(enabled no)
			(sheetname "")
		)
		(fill
			(thermal_gap 0.5)
			(thermal_bridge_width 0.5)
			(island_removal_mode 0)
		)
		(polygon
			(pts
				(xy 180.423058 -306.654962) (xy 180.423058 -306.426362) (xy 182.455058 -306.426362) (xy 182.455058 -306.654962)
			)
		)
	)
	(zone
		(layer "F.Cu")
		(hatch none 0.5)
		(connect_pads
			(clearance 0)
		)
		(min_thickness 0.25)
		(keepout
			(tracks allowed)
			(vias allowed)
			(pads allowed)
			(copperpour allowed)
			(footprints allowed)
		)
		(placement
			(enabled no)
			(sheetname "")
		)
		(fill
			(thermal_gap 0.5)
			(thermal_bridge_width 0.5)
			(island_removal_mode 0)
		)
		(polygon
			(pts
				(xy 292.67531 -295.716452) (xy 292.67531 -295.272714) (xy 295.000426 -295.272714) (xy 295.000426 -295.716452)
			)
		)
	)
	(zone
		(layer "F.Cu")
		(hatch none 0.5)
		(connect_pads
			(clearance 0)
		)
		(min_thickness 0.25)
		(keepout
			(tracks allowed)
			(vias allowed)
			(pads allowed)
			(copperpour allowed)
			(footprints allowed)
		)
		(placement
			(enabled no)
			(sheetname "")
		)
		(fill
			(thermal_gap 0.5)
			(thermal_bridge_width 0.5)
			(island_removal_mode 0)
		)
		(polygon
			(pts
				(xy 413.275526 -230.154988) (xy 413.275526 -229.926388) (xy 415.307526 -229.926388) (xy 415.307526 -230.154988)
			)
		)
	)
	(zone
		(layer "F.Cu")
		(hatch none 0.5)
		(connect_pads
			(clearance 0)
		)
		(min_thickness 0.25)
		(keepout
			(tracks allowed)
			(vias allowed)
			(pads allowed)
			(copperpour allowed)
			(footprints allowed)
		)
		(placement
			(enabled no)
			(sheetname "")
		)
		(fill
			(thermal_gap 0.5)
			(thermal_bridge_width 0.5)
			(island_removal_mode 0)
		)
		(polygon
			(pts
				(xy 398.535144 -404.802594) (xy 398.535144 -399.959576) (xy 400.41957 -399.959576) (xy 400.41957 -404.802594)
			)
		)
	)
	(zone
		(layer "F.Cu")
		(hatch none 0.5)
		(connect_pads
			(clearance 0)
		)
		(min_thickness 0.25)
		(keepout
			(tracks allowed)
			(vias allowed)
			(pads allowed)
			(copperpour allowed)
			(footprints allowed)
		)
		(placement
			(enabled no)
			(sheetname "")
		)
		(fill
			(thermal_gap 0.5)
			(thermal_bridge_width 0.5)
			(island_removal_mode 0)
		)
		(polygon
			(pts
				(xy 455.094594 -195.926456) (xy 457.126594 -195.926456) (xy 457.126594 -196.155056) (xy 455.094594 -196.155056)
				(xy 454.95845 -196.155056) (xy 454.91146 -196.155056) (xy 454.91146 -195.926456) (xy 454.95845 -195.926456)
			)
		)
	)
	(zone
		(layer "F.Cu")
		(hatch none 0.5)
		(connect_pads
			(clearance 0)
		)
		(min_thickness 0.25)
		(keepout
			(tracks allowed)
			(vias allowed)
			(pads allowed)
			(copperpour allowed)
			(footprints allowed)
		)
		(placement
			(enabled no)
			(sheetname "")
		)
		(fill
			(thermal_gap 0.5)
			(thermal_bridge_width 0.5)
			(island_removal_mode 0)
		)
		(polygon
			(pts
				(xy 207.154526 -229.926388) (xy 209.186526 -229.926388) (xy 209.186526 -230.154988) (xy 207.154526 -230.154988)
				(xy 207.018382 -230.154988) (xy 206.971392 -230.154988) (xy 206.971392 -229.926388) (xy 207.018382 -229.926388)
			)
		)
	)
	(zone
		(layer "F.Cu")
		(hatch none 0.5)
		(connect_pads
			(clearance 0)
		)
		(min_thickness 0.25)
		(keepout
			(tracks allowed)
			(vias allowed)
			(pads allowed)
			(copperpour allowed)
			(footprints allowed)
		)
		(placement
			(enabled no)
			(sheetname "")
		)
		(fill
			(thermal_gap 0.5)
			(thermal_bridge_width 0.5)
			(island_removal_mode 0)
		)
		(polygon
			(pts
				(xy 428.363126 -214.85479) (xy 428.363126 -214.62619) (xy 430.395126 -214.62619) (xy 430.395126 -214.85479)
			)
		)
	)
	(zone
		(layer "F.Cu")
		(hatch none 0.5)
		(connect_pads
			(clearance 0)
		)
		(min_thickness 0.25)
		(keepout
			(tracks allowed)
			(vias allowed)
			(pads allowed)
			(copperpour allowed)
			(footprints allowed)
		)
		(placement
			(enabled no)
			(sheetname "")
		)
		(fill
			(thermal_gap 0.5)
			(thermal_bridge_width 0.5)
			(island_removal_mode 0)
		)
		(polygon
			(pts
				(xy 44.735242 -250.666504) (xy 44.735242 -250.222766) (xy 47.060358 -250.222766) (xy 47.060358 -250.666504)
			)
		)
	)
	(zone
		(layer "F.Cu")
		(hatch none 0.5)
		(connect_pads
			(clearance 0)
		)
		(min_thickness 0.25)
		(keepout
			(tracks allowed)
			(vias allowed)
			(pads allowed)
			(copperpour allowed)
			(footprints not_allowed)
		)
		(placement
			(enabled no)
			(sheetname "")
		)
		(fill
			(thermal_gap 0.5)
			(thermal_bridge_width 0.5)
			(island_removal_mode 0)
		)
		(polygon
			(pts
				(arc
					(start 262.850122 -22.29993)
					(mid 265.650218 -19.499834)
					(end 268.45006 -22.29993)
				)
				(arc
					(start 268.45006 -22.29993)
					(mid 265.650218 -25.099772)
					(end 262.850122 -22.29993)
				)
			)
		)
	)
	(zone
		(layer "F.Cu")
		(hatch none 0.5)
		(connect_pads
			(clearance 0)
		)
		(min_thickness 0.25)
		(keepout
			(tracks allowed)
			(vias allowed)
			(pads allowed)
			(copperpour allowed)
			(footprints allowed)
		)
		(placement
			(enabled no)
			(sheetname "")
		)
		(fill
			(thermal_gap 0.5)
			(thermal_bridge_width 0.5)
			(island_removal_mode 0)
		)
		(polygon
			(pts
				(xy 262.50011 -197.116446) (xy 262.50011 -196.672708) (xy 264.825226 -196.672708) (xy 264.825226 -197.116446)
			)
		)
	)
	(zone
		(layer "F.Cu")
		(hatch none 0.5)
		(connect_pads
			(clearance 0)
		)
		(min_thickness 0.25)
		(keepout
			(tracks allowed)
			(vias allowed)
			(pads allowed)
			(copperpour allowed)
			(footprints not_allowed)
		)
		(placement
			(enabled no)
			(sheetname "")
		)
		(fill
			(thermal_gap 0.5)
			(thermal_bridge_width 0.5)
			(island_removal_mode 0)
		)
		(polygon
			(pts
				(xy 84.68995 -188.770006) (xy 139.939776 -188.770006) (xy 139.939776 -165.970712) (xy 84.68995 -165.970712)
			)
		)
	)
	(zone
		(layer "F.Cu")
		(hatch none 0.5)
		(connect_pads
			(clearance 0)
		)
		(min_thickness 0.25)
		(keepout
			(tracks allowed)
			(vias allowed)
			(pads allowed)
			(copperpour allowed)
			(footprints not_allowed)
		)
		(placement
			(enabled no)
			(sheetname "")
		)
		(fill
			(thermal_gap 0.5)
			(thermal_bridge_width 0.5)
			(island_removal_mode 0)
		)
		(polygon
			(pts
				(arc
					(start 162.900106 -160.50006)
					(mid 167.900096 -155.50007)
					(end 172.900086 -160.50006)
				)
				(arc
					(start 172.900086 -160.50006)
					(mid 167.900096 -165.50005)
					(end 162.900106 -160.50006)
				)
			)
		)
	)
	(zone
		(layer "F.Cu")
		(hatch none 0.5)
		(connect_pads
			(clearance 0)
		)
		(min_thickness 0.25)
		(keepout
			(tracks allowed)
			(vias allowed)
			(pads allowed)
			(copperpour allowed)
			(footprints allowed)
		)
		(placement
			(enabled no)
			(sheetname "")
		)
		(fill
			(thermal_gap 0.5)
			(thermal_bridge_width 0.5)
			(island_removal_mode 0)
		)
		(polygon
			(pts
				(xy 413.275526 -310.055006) (xy 413.275526 -309.826406) (xy 415.307526 -309.826406) (xy 415.307526 -310.055006)
			)
		)
	)
	(zone
		(layer "F.Cu")
		(hatch none 0.5)
		(connect_pads
			(clearance 0)
		)
		(min_thickness 0.25)
		(keepout
			(tracks allowed)
			(vias allowed)
			(pads allowed)
			(copperpour allowed)
			(footprints allowed)
		)
		(placement
			(enabled no)
			(sheetname "")
		)
		(fill
			(thermal_gap 0.5)
			(thermal_bridge_width 0.5)
			(island_removal_mode 0)
		)
		(polygon
			(pts
				(xy 289.231578 -201.366628) (xy 289.231578 -200.92289) (xy 291.556694 -200.92289) (xy 291.556694 -201.366628)
			)
		)
	)
	(zone
		(layer "F.Cu")
		(hatch none 0.5)
		(connect_pads
			(clearance 0)
		)
		(min_thickness 0.25)
		(keepout
			(tracks allowed)
			(vias allowed)
			(pads allowed)
			(copperpour allowed)
			(footprints allowed)
		)
		(placement
			(enabled no)
			(sheetname "")
		)
		(fill
			(thermal_gap 0.5)
			(thermal_bridge_width 0.5)
			(island_removal_mode 0)
		)
		(polygon
			(pts
				(xy 87.345012 -404.802594) (xy 87.345012 -399.959576) (xy 89.229438 -399.959576) (xy 89.229438 -404.802594)
			)
		)
	)
	(zone
		(layer "F.Cu")
		(hatch none 0.5)
		(connect_pads
			(clearance 0)
		)
		(min_thickness 0.25)
		(keepout
			(tracks allowed)
			(vias allowed)
			(pads allowed)
			(copperpour allowed)
			(footprints allowed)
		)
		(placement
			(enabled no)
			(sheetname "")
		)
		(fill
			(thermal_gap 0.5)
			(thermal_bridge_width 0.5)
			(island_removal_mode 0)
		)
		(polygon
			(pts
				(xy 44.735242 -264.266426) (xy 44.735242 -263.822688) (xy 47.060358 -263.822688) (xy 47.060358 -264.266426)
			)
		)
	)
	(zone
		(layer "F.Cu")
		(hatch none 0.5)
		(connect_pads
			(clearance 0)
		)
		(min_thickness 0.25)
		(keepout
			(tracks allowed)
			(vias allowed)
			(pads allowed)
			(copperpour allowed)
			(footprints allowed)
		)
		(placement
			(enabled no)
			(sheetname "")
		)
		(fill
			(thermal_gap 0.5)
			(thermal_bridge_width 0.5)
			(island_removal_mode 0)
		)
		(polygon
			(pts
				(xy 56.37911 -304.216562) (xy 56.37911 -303.772824) (xy 58.704226 -303.772824) (xy 58.704226 -304.216562)
			)
		)
	)
	(zone
		(layer "F.Cu")
		(hatch none 0.5)
		(connect_pads
			(clearance 0)
		)
		(min_thickness 0.25)
		(keepout
			(tracks allowed)
			(vias allowed)
			(pads allowed)
			(copperpour allowed)
			(footprints allowed)
		)
		(placement
			(enabled no)
			(sheetname "")
		)
		(fill
			(thermal_gap 0.5)
			(thermal_bridge_width 0.5)
			(island_removal_mode 0)
		)
		(polygon
			(pts
				(xy 180.423058 -270.955008) (xy 180.423058 -270.726408) (xy 182.455058 -270.726408) (xy 182.455058 -270.955008)
			)
		)
	)
	(zone
		(layer "F.Cu")
		(hatch none 0.5)
		(connect_pads
			(clearance 0)
		)
		(min_thickness 0.25)
		(keepout
			(tracks allowed)
			(vias allowed)
			(pads allowed)
			(copperpour allowed)
			(footprints allowed)
		)
		(placement
			(enabled no)
			(sheetname "")
		)
		(fill
			(thermal_gap 0.5)
			(thermal_bridge_width 0.5)
			(island_removal_mode 0)
		)
		(polygon
			(pts
				(xy 440.006994 -258.826254) (xy 442.038994 -258.826254) (xy 442.038994 -259.054854) (xy 440.006994 -259.054854)
				(xy 439.831226 -259.054854) (xy 439.831226 -258.826254)
			)
		)
	)
	(zone
		(layer "F.Cu")
		(hatch none 0.5)
		(connect_pads
			(clearance 0)
		)
		(min_thickness 0.25)
		(keepout
			(tracks allowed)
			(vias allowed)
			(pads allowed)
			(copperpour allowed)
			(footprints allowed)
		)
		(placement
			(enabled no)
			(sheetname "")
		)
		(fill
			(thermal_gap 0.5)
			(thermal_bridge_width 0.5)
			(island_removal_mode 0)
		)
		(polygon
			(pts
				(xy 138.331448 -280.37409) (xy 137.740644 -280.37409) (xy 136.373108 -279.006554) (xy 136.372854 -275.18995)
				(xy 135.907018 -274.72386) (xy 135.907018 -274.702524) (xy 135.907018 -253.71806) (xy 135.642604 -253.453646)
				(xy 135.203692 -253.014734) (xy 133.88213 -253.014734) (xy 133.196838 -252.329442) (xy 132.04317 -251.175774)
				(xy 132.04317 -248.675398) (xy 132.871464 -247.847104) (xy 134.903464 -247.847104) (xy 135.810498 -246.94007)
				(xy 135.80999 -227.200206) (xy 137.807192 -225.203004) (xy 138.65352 -225.203004) (xy 138.6586 -225.197924)
				(xy 139.10691 -225.197924) (xy 139.230862 -225.073972) (xy 139.317222 -224.987612) (xy 139.402312 -224.987612)
				(xy 140.175488 -225.760788) (xy 140.175488 -226.114356) (xy 140.062712 -226.227132) (xy 140.062712 -226.264724)
				(xy 140.455396 -226.657408) (xy 140.455396 -226.716844) (xy 140.294614 -226.877626) (xy 140.294614 -226.976686)
				(xy 140.645642 -227.327714) (xy 140.645642 -227.40112) (xy 140.437362 -227.6094) (xy 140.437362 -227.692458)
				(xy 141.04239 -228.297486) (xy 141.04239 -228.358954) (xy 140.612114 -228.78923) (xy 140.612114 -228.830886)
				(xy 140.719048 -228.93782) (xy 140.778738 -228.93782) (xy 141.11986 -228.596698) (xy 141.25829 -228.596698)
				(xy 141.732508 -229.070916) (xy 141.732508 -229.233476) (xy 140.568426 -230.397558) (xy 140.568426 -230.500428)
				(xy 141.153388 -231.08539) (xy 141.153388 -231.190546) (xy 140.235178 -232.108756) (xy 140.235178 -232.160318)
				(xy 140.800328 -232.725468) (xy 140.800328 -232.866438) (xy 140.514832 -233.151934) (xy 140.514832 -233.734864)
				(xy 140.437362 -233.812334) (xy 140.437362 -235.059474) (xy 140.49502 -235.117132) (xy 141.155166 -235.117132)
				(xy 141.232636 -235.194602) (xy 141.232636 -236.441996) (xy 141.262354 -236.471714) (xy 141.262354 -237.090458)
				(xy 141.2367 -237.116112) (xy 141.030452 -237.116112) (xy 140.845794 -237.116112) (xy 140.807694 -237.154212)
				(xy 140.807694 -237.559596) (xy 140.918184 -237.670086) (xy 141.015974 -237.670086) (xy 141.038072 -237.692184)
				(xy 141.038072 -238.494824) (xy 141.045438 -238.50219) (xy 141.282166 -238.50219) (xy 141.377416 -238.59744)
				(xy 141.377416 -238.829596) (xy 141.115796 -239.091216) (xy 140.927582 -239.091216) (xy 140.267182 -239.751616)
				(xy 140.267182 -239.886744) (xy 140.502894 -240.122456) (xy 140.502894 -240.207546) (xy 140.257022 -240.453418)
				(xy 140.257022 -240.54054) (xy 140.786612 -241.07013) (xy 140.832332 -241.07013) (xy 141.53642 -240.366042)
				(xy 141.960346 -240.366042) (xy 142.014194 -240.41989) (xy 142.014194 -240.983008) (xy 141.982444 -241.014758)
				(xy 141.70279 -241.014758) (xy 140.64361 -242.073938) (xy 140.64361 -242.115086) (xy 140.982954 -242.45443)
				(xy 140.982954 -242.614958) (xy 140.249148 -243.348764) (xy 140.249148 -244.939566) (xy 140.397738 -245.088156)
				(xy 140.397738 -246.68226) (xy 140.43152 -246.716042) (xy 140.80617 -246.716042) (xy 140.846048 -246.75592)
				(xy 140.846048 -247.090946) (xy 140.794486 -247.142508) (xy 140.794486 -247.334786) (xy 141.659102 -248.199402)
				(xy 141.659102 -248.340118) (xy 141.657324 -248.341896) (xy 141.657324 -248.425462) (xy 141.792198 -248.560336)
				(xy 141.792198 -248.675144) (xy 140.223494 -250.243848) (xy 138.895074 -250.243848) (xy 138.86307 -250.275852)
				(xy 138.86307 -250.432316) (xy 138.607038 -250.688348) (xy 137.242804 -250.688348) (xy 137.19937 -250.731782)
				(xy 137.19937 -250.98756) (xy 137.164572 -251.022358) (xy 137.070338 -251.022358) (xy 136.766554 -251.022358)
				(xy 136.584436 -250.84024) (xy 136.11606 -250.84024) (xy 135.715248 -250.439428) (xy 135.715248 -250.109228)
				(xy 135.561324 -249.955304) (xy 132.64896 -249.955304) (xy 132.54609 -250.058174) (xy 132.54609 -250.244356)
				(xy 132.596128 -250.244356) (xy 132.996178 -250.644406) (xy 133.308344 -250.8631) (xy 134.912608 -251.705618)
				(xy 135.357108 -251.900944) (xy 135.357108 -251.901452) (xy 135.420608 -251.940822) (xy 135.420608 -252.153674)
				(xy 135.471662 -252.204728) (xy 135.98906 -252.521212) (xy 136.534652 -252.654562) (xy 136.565132 -252.685042)
				(xy 136.565132 -252.854968) (xy 136.841484 -253.13132) (xy 136.891268 -253.13132) (xy 138.583416 -253.13132)
				(xy 140.479272 -253.527814) (xy 140.497052 -253.545594) (xy 140.497052 -253.844298) (xy 140.467842 -253.873508)
				(xy 140.467842 -253.910592) (xy 140.52931 -253.97206) (xy 140.648436 -253.97206) (xy 140.944854 -254.268478)
				(xy 140.944854 -254.533908) (xy 140.895578 -254.583184) (xy 140.387578 -254.583184) (xy 140.374116 -254.596646)
				(xy 140.374116 -255.411732) (xy 140.247116 -255.538732) (xy 140.10259 -255.538732) (xy 139.977622 -255.6637)
				(xy 139.977622 -255.852168) (xy 140.074396 -255.948942) (xy 140.074396 -257.549904) (xy 141.051026 -258.52628)
				(xy 141.051026 -258.570476) (xy 142.042134 -259.561838) (xy 142.067534 -259.587238) (xy 142.067534 -259.736844)
				(xy 141.234668 -260.56971) (xy 141.234668 -260.595618) (xy 142.436342 -261.797292) (xy 142.436342 -261.880858)
				(xy 142.026132 -262.291068) (xy 141.9606 -262.291068) (xy 141.722602 -262.05307) (xy 141.323314 -261.653782)
				(xy 141.284198 -261.653782) (xy 140.988542 -261.949438) (xy 140.988542 -262.025638) (xy 141.087602 -262.124698)
				(xy 141.087602 -262.259826) (xy 141.050264 -262.297164) (xy 140.253212 -263.094216) (xy 140.253212 -263.254744)
				(xy 141.371574 -264.373106) (xy 141.371574 -264.537952) (xy 140.776706 -265.13282) (xy 140.617956 -265.13282)
				(xy 140.14196 -264.656824) (xy 140.078714 -264.656824) (xy 139.94765 -264.787888) (xy 139.94765 -264.859262)
				(xy 141.143482 -266.055094) (xy 141.143482 -266.261088) (xy 140.419836 -266.984734) (xy 140.419836 -267.028676)
				(xy 140.658596 -267.267436) (xy 140.658596 -267.32103) (xy 140.450062 -267.529564) (xy 140.318744 -267.529564)
				(xy 140.114528 -267.325348) (xy 140.093192 -267.325348) (xy 139.370816 -268.047724) (xy 139.370816 -268.095476)
				(xy 141.167358 -269.892018) (xy 141.167358 -270.023082) (xy 140.830046 -270.360394) (xy 140.830046 -270.425672)
				(xy 140.923264 -270.51889) (xy 140.923264 -270.774668) (xy 140.201904 -271.496028) (xy 140.164566 -271.496028)
				(xy 140.109702 -271.44091) (xy 140.09624 -271.427448) (xy 139.958064 -271.427448) (xy 139.638532 -271.74698)
				(xy 139.638532 -271.85112) (xy 139.685268 -271.897856) (xy 139.742672 -271.95526) (xy 139.762992 -271.975834)
				(xy 141.439392 -273.652234) (xy 141.439138 -273.652488) (xy 141.460728 -273.673824) (xy 141.460728 -273.790918)
				(xy 141.302232 -273.949414) (xy 141.206982 -273.949414) (xy 140.362178 -273.10461) (xy 140.342366 -273.10461)
				(xy 140.18768 -273.259296) (xy 140.18768 -273.30908) (xy 141.00683 -274.12823) (xy 141.00683 -274.258786)
				(xy 140.606018 -274.659598) (xy 140.606018 -274.812252) (xy 140.120116 -275.298154) (xy 140.120116 -275.313648)
				(xy 140.312394 -275.505926) (xy 140.312394 -275.585428) (xy 139.90193 -275.995892) (xy 139.90193 -276.023578)
				(xy 139.90193 -276.206204) (xy 140.130022 -276.434296) (xy 140.130022 -276.51202) (xy 139.630404 -277.011638)
				(xy 139.630404 -277.161498) (xy 139.630658 -277.161752) (xy 139.195302 -277.597108) (xy 139.195302 -277.605744)
				(xy 139.344146 -277.754588) (xy 139.634722 -278.045164) (xy 139.634722 -278.655018) (xy 139.737338 -278.757634)
				(xy 139.737338 -279.357074) (xy 139.95273 -279.57272) (xy 139.95273 -280.115772) (xy 140.130276 -280.293318)
				(xy 140.130276 -281.069288) (xy 140.130276 -281.161998) (xy 140.113766 -281.178508) (xy 138.988546 -281.178508)
				(xy 138.867388 -281.05735) (xy 138.867388 -280.91003)
			)
		)
	)
	(zone
		(layer "F.Cu")
		(hatch none 0.5)
		(connect_pads
			(clearance 0)
		)
		(min_thickness 0.25)
		(keepout
			(tracks allowed)
			(vias allowed)
			(pads allowed)
			(copperpour allowed)
			(footprints allowed)
		)
		(placement
			(enabled no)
			(sheetname "")
		)
		(fill
			(thermal_gap 0.5)
			(thermal_bridge_width 0.5)
			(island_removal_mode 0)
		)
		(polygon
			(pts
				(xy 289.231578 -271.066514) (xy 289.231578 -270.622776) (xy 291.556694 -270.622776) (xy 291.556694 -271.066514)
			)
		)
	)
	(zone
		(layer "F.Cu")
		(hatch none 0.5)
		(connect_pads
			(clearance 0)
		)
		(min_thickness 0.25)
		(keepout
			(tracks allowed)
			(vias allowed)
			(pads allowed)
			(copperpour allowed)
			(footprints not_allowed)
		)
		(placement
			(enabled no)
			(sheetname "")
		)
		(fill
			(thermal_gap 0.5)
			(thermal_bridge_width 0.5)
			(island_removal_mode 0)
		)
		(polygon
			(pts
				(xy 116.225066 -261.62) (xy 119.85498 -261.62) (xy 119.85498 -237.00994) (xy 116.225066 -237.00994)
			)
		)
	)
	(zone
		(layer "F.Cu")
		(hatch none 0.5)
		(connect_pads
			(clearance 0)
		)
		(min_thickness 0.25)
		(keepout
			(tracks allowed)
			(vias allowed)
			(pads allowed)
			(copperpour allowed)
			(footprints allowed)
		)
		(placement
			(enabled no)
			(sheetname "")
		)
		(fill
			(thermal_gap 0.5)
			(thermal_bridge_width 0.5)
			(island_removal_mode 0)
		)
		(polygon
			(pts
				(xy 395.298676 -229.09657) (xy 389.236712 -235.158788) (xy 389.236204 -235.158788) (xy 389.236204 -235.194348)
				(xy 389.172704 -235.257848) (xy 389.172704 -236.441996) (xy 389.202422 -236.471714) (xy 389.202422 -237.090458)
				(xy 389.176768 -237.116112) (xy 388.97052 -237.116112) (xy 388.785862 -237.116112) (xy 388.747762 -237.154212)
				(xy 388.747762 -237.559596) (xy 388.858252 -237.670086) (xy 388.956042 -237.670086) (xy 388.97814 -237.692184)
				(xy 388.97814 -238.49584) (xy 388.984744 -238.502444) (xy 389.222488 -238.502444) (xy 389.317484 -238.59744)
				(xy 389.317484 -238.87557) (xy 390.80313 -238.87557) (xy 397.225266 -232.453434) (xy 397.428974 -232.453434)
				(xy 398.006316 -231.876092) (xy 398.903952 -231.876092) (xy 399.130266 -231.876092) (xy 399.157698 -231.84866)
				(xy 399.157698 -230.521002) (xy 399.157698 -230.471472) (xy 399.242026 -230.387144) (xy 399.242026 -229.287324)
				(xy 399.157698 -229.202996) (xy 398.051274 -228.096572) (xy 398.051274 -227.435664) (xy 398.051274 -227.32746)
				(xy 397.465042 -226.741228) (xy 397.465042 -226.188524) (xy 397.465042 -226.085908) (xy 396.021306 -224.642172)
				(xy 396.236698 -224.427034) (xy 395.931898 -224.122234) (xy 395.931898 -223.334834) (xy 395.931898 -223.252284)
				(xy 395.301978 -223.252284) (xy 395.298676 -223.255332) (xy 395.298676 -223.334834)
			)
		)
	)
	(zone
		(layer "F.Cu")
		(hatch none 0.5)
		(connect_pads
			(clearance 0)
		)
		(min_thickness 0.25)
		(keepout
			(tracks allowed)
			(vias allowed)
			(pads allowed)
			(copperpour allowed)
			(footprints allowed)
		)
		(placement
			(enabled no)
			(sheetname "")
		)
		(fill
			(thermal_gap 0.5)
			(thermal_bridge_width 0.5)
			(island_removal_mode 0)
		)
		(polygon
			(pts
				(xy 259.056378 -314.41644) (xy 259.056378 -313.972702) (xy 261.381494 -313.972702) (xy 261.381494 -314.41644)
			)
		)
	)
	(zone
		(layer "F.Cu")
		(hatch none 0.5)
		(connect_pads
			(clearance 0)
		)
		(min_thickness 0.25)
		(keepout
			(tracks allowed)
			(vias allowed)
			(pads allowed)
			(copperpour allowed)
			(footprints not_allowed)
		)
		(placement
			(enabled no)
			(sheetname "")
		)
		(fill
			(thermal_gap 0.5)
			(thermal_bridge_width 0.5)
			(island_removal_mode 0)
		)
		(polygon
			(pts
				(xy 87.908638 -355.763576) (xy 130.48107 -355.763576) (xy 130.48107 -345.424252)
				(arc
					(start 126.321566 -345.424252)
					(mid 125.402347 -345.043499)
					(end 125.021594 -344.12428)
				)
				(xy 125.021594 -339.691472) (xy 93.939614 -339.691472)
				(arc
					(start 93.939614 -344.12428)
					(mid 93.558861 -345.043499)
					(end 92.639642 -345.424252)
				)
				(xy 87.908638 -345.424252)
			)
		)
	)
	(zone
		(layer "F.Cu")
		(hatch none 0.5)
		(connect_pads
			(clearance 0)
		)
		(min_thickness 0.25)
		(keepout
			(tracks allowed)
			(vias allowed)
			(pads allowed)
			(copperpour allowed)
			(footprints allowed)
		)
		(placement
			(enabled no)
			(sheetname "")
		)
		(fill
			(thermal_gap 0.5)
			(thermal_bridge_width 0.5)
			(island_removal_mode 0)
		)
		(polygon
			(pts
				(xy 59.822842 -227.716588) (xy 59.822842 -227.27285) (xy 62.147958 -227.27285) (xy 62.147958 -227.716588)
			)
		)
	)
	(zone
		(layer "F.Cu")
		(hatch none 0.5)
		(connect_pads
			(clearance 0)
		)
		(min_thickness 0.25)
		(keepout
			(tracks allowed)
			(vias allowed)
			(pads allowed)
			(copperpour allowed)
			(footprints allowed)
		)
		(placement
			(enabled no)
			(sheetname "")
		)
		(fill
			(thermal_gap 0.5)
			(thermal_bridge_width 0.5)
			(island_removal_mode 0)
		)
		(polygon
			(pts
				(xy 282.21686 -411.05328) (xy 284.3149 -411.05328) (xy 284.4927 -410.87548) (xy 284.4927 -407.81732)
				(xy 283.5529 -406.87752) (xy 282.34894 -406.87752) (xy 282.02382 -407.20264) (xy 282.02382 -410.86024)
			)
		)
	)
	(zone
		(layer "F.Cu")
		(hatch none 0.5)
		(connect_pads
			(clearance 0)
		)
		(min_thickness 0.25)
		(keepout
			(tracks allowed)
			(vias allowed)
			(pads allowed)
			(copperpour allowed)
			(footprints allowed)
		)
		(placement
			(enabled no)
			(sheetname "")
		)
		(fill
			(thermal_gap 0.5)
			(thermal_bridge_width 0.5)
			(island_removal_mode 0)
		)
		(polygon
			(pts
				(xy 44.735242 -293.166546) (xy 44.735242 -292.722808) (xy 47.060358 -292.722808) (xy 47.060358 -293.166546)
			)
		)
	)
	(zone
		(layer "F.Cu")
		(hatch none 0.5)
		(connect_pads
			(clearance 0)
		)
		(min_thickness 0.25)
		(keepout
			(tracks allowed)
			(vias allowed)
			(pads allowed)
			(copperpour allowed)
			(footprints allowed)
		)
		(placement
			(enabled no)
			(sheetname "")
		)
		(fill
			(thermal_gap 0.5)
			(thermal_bridge_width 0.5)
			(island_removal_mode 0)
		)
		(polygon
			(pts
				(xy 333.25816 -286.581088) (xy 333.54518 -286.581088) (xy 333.57566 -286.550608) (xy 333.57566 -285.923228)
				(xy 333.4893 -285.836868) (xy 333.30134 -285.836868) (xy 333.22768 -285.910528) (xy 333.22768 -286.550608)
			)
		)
	)
	(zone
		(layer "F.Cu")
		(hatch none 0.5)
		(connect_pads
			(clearance 0)
		)
		(min_thickness 0.25)
		(keepout
			(tracks allowed)
			(vias allowed)
			(pads allowed)
			(copperpour allowed)
			(footprints allowed)
		)
		(placement
			(enabled no)
			(sheetname "")
		)
		(fill
			(thermal_gap 0.5)
			(thermal_bridge_width 0.5)
			(island_removal_mode 0)
		)
		(polygon
			(pts
				(xy 213.0806 -15.608808) (xy 213.0806 -14.077188) (xy 215.34628 -14.077188) (xy 215.34628 -15.608808)
			)
		)
	)
	(zone
		(layer "F.Cu")
		(hatch none 0.5)
		(connect_pads
			(clearance 0)
		)
		(min_thickness 0.25)
		(keepout
			(tracks allowed)
			(vias allowed)
			(pads allowed)
			(copperpour allowed)
			(footprints allowed)
		)
		(placement
			(enabled no)
			(sheetname "")
		)
		(fill
			(thermal_gap 0.5)
			(thermal_bridge_width 0.5)
			(island_removal_mode 0)
		)
		(polygon
			(pts
				(xy 424.919394 -222.276416) (xy 426.951394 -222.276416) (xy 426.951394 -222.505016) (xy 424.919394 -222.505016)
				(xy 424.78325 -222.505016) (xy 424.73626 -222.505016) (xy 424.73626 -222.276416) (xy 424.78325 -222.276416)
			)
		)
	)
	(zone
		(layer "F.Cu")
		(hatch none 0.5)
		(connect_pads
			(clearance 0)
		)
		(min_thickness 0.25)
		(keepout
			(tracks allowed)
			(vias allowed)
			(pads allowed)
			(copperpour allowed)
			(footprints allowed)
		)
		(placement
			(enabled no)
			(sheetname "")
		)
		(fill
			(thermal_gap 0.5)
			(thermal_bridge_width 0.5)
			(island_removal_mode 0)
		)
		(polygon
			(pts
				(xy 405.731726 -265.004804) (xy 405.731726 -264.776204) (xy 407.763726 -264.776204) (xy 407.763726 -265.004804)
			)
		)
	)
	(zone
		(layer "F.Cu")
		(hatch none 0.5)
		(connect_pads
			(clearance 0)
		)
		(min_thickness 0.25)
		(keepout
			(tracks allowed)
			(vias allowed)
			(pads allowed)
			(copperpour allowed)
			(footprints allowed)
		)
		(placement
			(enabled no)
			(sheetname "")
		)
		(fill
			(thermal_gap 0.5)
			(thermal_bridge_width 0.5)
			(island_removal_mode 0)
		)
		(polygon
			(pts
				(xy 259.056378 -316.116462) (xy 259.056378 -315.672724) (xy 261.381494 -315.672724) (xy 261.381494 -316.116462)
			)
		)
	)
	(zone
		(layer "F.Cu")
		(hatch none 0.5)
		(connect_pads
			(clearance 0)
		)
		(min_thickness 0.25)
		(keepout
			(tracks allowed)
			(vias allowed)
			(pads allowed)
			(copperpour allowed)
			(footprints allowed)
		)
		(placement
			(enabled no)
			(sheetname "")
		)
		(fill
			(thermal_gap 0.5)
			(thermal_bridge_width 0.5)
			(island_removal_mode 0)
		)
		(polygon
			(pts
				(xy 413.62757 -360.061002) (xy 413.62757 -364.066582) (xy 414.10763 -364.546642) (xy 416.17265 -364.546642)
				(xy 416.44443 -364.274862) (xy 416.44443 -362.420662) (xy 416.69589 -362.169202) (xy 418.61613 -362.169202)
				(xy 419.03269 -361.752642) (xy 419.03269 -360.261662) (xy 418.38499 -359.613962) (xy 414.07461 -359.613962)
			)
		)
	)
	(zone
		(layer "F.Cu")
		(hatch none 0.5)
		(connect_pads
			(clearance 0)
		)
		(min_thickness 0.25)
		(keepout
			(tracks not_allowed)
			(vias allowed)
			(pads allowed)
			(copperpour not_allowed)
			(footprints allowed)
		)
		(placement
			(enabled no)
			(sheetname "")
		)
		(fill
			(thermal_gap 0.5)
			(thermal_bridge_width 0.5)
			(island_removal_mode 0)
		)
		(polygon
			(pts
				(arc
					(start 462.799938 -22.29993)
					(mid 464.799934 -20.299934)
					(end 466.79993 -22.29993)
				)
				(arc
					(start 466.79993 -22.29993)
					(mid 464.799934 -24.299926)
					(end 462.799938 -22.29993)
				)
			)
		)
	)
	(zone
		(layer "F.Cu")
		(hatch none 0.5)
		(connect_pads
			(clearance 0)
		)
		(min_thickness 0.25)
		(keepout
			(tracks allowed)
			(vias allowed)
			(pads allowed)
			(copperpour allowed)
			(footprints allowed)
		)
		(placement
			(enabled no)
			(sheetname "")
		)
		(fill
			(thermal_gap 0.5)
			(thermal_bridge_width 0.5)
			(island_removal_mode 0)
		)
		(polygon
			(pts
				(xy 409.831794 -202.105006) (xy 409.831794 -201.876406) (xy 411.863794 -201.876406) (xy 411.863794 -202.105006)
			)
		)
	)
	(zone
		(layer "F.Cu")
		(hatch none 0.5)
		(connect_pads
			(clearance 0)
		)
		(min_thickness 0.25)
		(keepout
			(tracks allowed)
			(vias allowed)
			(pads allowed)
			(copperpour allowed)
			(footprints allowed)
		)
		(placement
			(enabled no)
			(sheetname "")
		)
		(fill
			(thermal_gap 0.5)
			(thermal_bridge_width 0.5)
			(island_removal_mode 0)
		)
		(polygon
			(pts
				(xy 180.423058 -264.15492) (xy 180.423058 -263.92632) (xy 182.455058 -263.92632) (xy 182.455058 -264.15492)
			)
		)
	)
	(zone
		(layer "F.Cu")
		(hatch none 0.5)
		(connect_pads
			(clearance 0)
		)
		(min_thickness 0.25)
		(keepout
			(tracks allowed)
			(vias allowed)
			(pads allowed)
			(copperpour allowed)
			(footprints not_allowed)
		)
		(placement
			(enabled no)
			(sheetname "")
		)
		(fill
			(thermal_gap 0.5)
			(thermal_bridge_width 0.5)
			(island_removal_mode 0)
		)
		(polygon
			(pts
				(arc
					(start 159.900112 -160.50006)
					(mid 167.900096 -152.500076)
					(end 175.90008 -160.50006)
				)
				(arc
					(start 175.90008 -160.50006)
					(mid 167.900096 -168.500044)
					(end 159.900112 -160.50006)
				)
			)
		)
	)
	(zone
		(layer "F.Cu")
		(hatch none 0.5)
		(connect_pads
			(clearance 0)
		)
		(min_thickness 0.25)
		(keepout
			(tracks allowed)
			(vias allowed)
			(pads allowed)
			(copperpour allowed)
			(footprints allowed)
		)
		(placement
			(enabled no)
			(sheetname "")
		)
		(fill
			(thermal_gap 0.5)
			(thermal_bridge_width 0.5)
			(island_removal_mode 0)
		)
		(polygon
			(pts
				(xy 455.094594 -229.07625) (xy 457.126594 -229.07625) (xy 457.126594 -229.30485) (xy 455.094594 -229.30485)
				(xy 454.963276 -229.30485) (xy 454.937368 -229.30485) (xy 454.937368 -229.07625) (xy 454.963276 -229.07625)
			)
		)
	)
	(zone
		(layer "F.Cu")
		(hatch none 0.5)
		(connect_pads
			(clearance 0)
		)
		(min_thickness 0.25)
		(keepout
			(tracks allowed)
			(vias allowed)
			(pads allowed)
			(copperpour allowed)
			(footprints allowed)
		)
		(placement
			(enabled no)
			(sheetname "")
		)
		(fill
			(thermal_gap 0.5)
			(thermal_bridge_width 0.5)
			(island_removal_mode 0)
		)
		(polygon
			(pts
				(xy 26.20391 -239.17275) (xy 28.529026 -239.17275) (xy 28.590494 -239.17275) (xy 28.590494 -240.096802)
				(xy 26.073862 -240.096802) (xy 26.073862 -239.17275)
			)
		)
	)
	(zone
		(layer "F.Cu")
		(hatch none 0.5)
		(connect_pads
			(clearance 0)
		)
		(min_thickness 0.25)
		(keepout
			(tracks allowed)
			(vias allowed)
			(pads allowed)
			(copperpour allowed)
			(footprints allowed)
		)
		(placement
			(enabled no)
			(sheetname "")
		)
		(fill
			(thermal_gap 0.5)
			(thermal_bridge_width 0.5)
			(island_removal_mode 0)
		)
		(polygon
			(pts
				(xy 424.919394 -275.82622) (xy 426.951394 -275.82622) (xy 426.951394 -276.05482) (xy 424.919394 -276.05482)
				(xy 424.788076 -276.05482) (xy 424.762168 -276.05482) (xy 424.762168 -275.82622) (xy 424.788076 -275.82622)
			)
		)
	)
	(zone
		(layer "F.Cu")
		(hatch none 0.5)
		(connect_pads
			(clearance 0)
		)
		(min_thickness 0.25)
		(keepout
			(tracks allowed)
			(vias allowed)
			(pads allowed)
			(copperpour allowed)
			(footprints allowed)
		)
		(placement
			(enabled no)
			(sheetname "")
		)
		(fill
			(thermal_gap 0.5)
			(thermal_bridge_width 0.5)
			(island_removal_mode 0)
		)
		(polygon
			(pts
				(xy 14.560042 -301.666656) (xy 14.560042 -301.222918) (xy 16.885158 -301.222918) (xy 16.885158 -301.666656)
			)
		)
	)
	(zone
		(layer "F.Cu")
		(hatch none 0.5)
		(connect_pads
			(clearance 0)
		)
		(min_thickness 0.25)
		(keepout
			(tracks allowed)
			(vias allowed)
			(pads allowed)
			(copperpour allowed)
			(footprints allowed)
		)
		(placement
			(enabled no)
			(sheetname "")
		)
		(fill
			(thermal_gap 0.5)
			(thermal_bridge_width 0.5)
			(island_removal_mode 0)
		)
		(polygon
			(pts
				(xy 344.929206 -335.958942) (xy 343.181686 -335.958942) (xy 343.181686 -334.023462) (xy 344.929206 -334.023462)
			)
		)
	)
	(zone
		(layer "F.Cu")
		(hatch none 0.5)
		(connect_pads
			(clearance 0)
		)
		(min_thickness 0.25)
		(keepout
			(tracks not_allowed)
			(vias allowed)
			(pads allowed)
			(copperpour not_allowed)
			(footprints allowed)
		)
		(placement
			(enabled no)
			(sheetname "")
		)
		(fill
			(thermal_gap 0.5)
			(thermal_bridge_width 0.5)
			(island_removal_mode 0)
		)
		(polygon
			(pts
				(arc
					(start 298.76496 -66.060828)
					(mid 293.00297 -60.298838)
					(end 287.24098 -66.060828)
				)
				(arc
					(start 287.24098 -74.760836)
					(mid 293.00297 -80.522826)
					(end 298.76496 -74.760836)
				)
			)
		)
	)
	(zone
		(layer "F.Cu")
		(hatch none 0.5)
		(connect_pads
			(clearance 0)
		)
		(min_thickness 0.25)
		(keepout
			(tracks allowed)
			(vias allowed)
			(pads allowed)
			(copperpour allowed)
			(footprints allowed)
		)
		(placement
			(enabled no)
			(sheetname "")
		)
		(fill
			(thermal_gap 0.5)
			(thermal_bridge_width 0.5)
			(island_removal_mode 0)
		)
		(polygon
			(pts
				(xy 423.366184 -18.55978) (xy 423.366184 -15.425166) (xy 425.144946 -15.425166) (xy 425.144946 -18.55978)
			)
		)
	)
	(zone
		(layer "F.Cu")
		(hatch none 0.5)
		(connect_pads
			(clearance 0)
		)
		(min_thickness 0.25)
		(keepout
			(tracks allowed)
			(vias allowed)
			(pads allowed)
			(copperpour allowed)
			(footprints allowed)
		)
		(placement
			(enabled no)
			(sheetname "")
		)
		(fill
			(thermal_gap 0.5)
			(thermal_bridge_width 0.5)
			(island_removal_mode 0)
		)
		(polygon
			(pts
				(xy 212.286342 -395.09446) (xy 212.286342 -391.81786) (xy 215.687402 -391.81786) (xy 215.687402 -395.09446)
			)
		)
	)
	(zone
		(layer "F.Cu")
		(hatch none 0.5)
		(connect_pads
			(clearance 0)
		)
		(min_thickness 0.25)
		(keepout
			(tracks allowed)
			(vias allowed)
			(pads allowed)
			(copperpour allowed)
			(footprints allowed)
		)
		(placement
			(enabled no)
			(sheetname "")
		)
		(fill
			(thermal_gap 0.5)
			(thermal_bridge_width 0.5)
			(island_removal_mode 0)
		)
		(polygon
			(pts
				(xy 418.260784 -410.948886) (xy 418.260784 -406.105868) (xy 420.14521 -406.105868) (xy 420.14521 -410.948886)
			)
		)
	)
	(zone
		(layer "F.Cu")
		(hatch none 0.5)
		(connect_pads
			(clearance 0)
		)
		(min_thickness 0.25)
		(keepout
			(tracks allowed)
			(vias allowed)
			(pads allowed)
			(copperpour allowed)
			(footprints allowed)
		)
		(placement
			(enabled no)
			(sheetname "")
		)
		(fill
			(thermal_gap 0.5)
			(thermal_bridge_width 0.5)
			(island_removal_mode 0)
		)
		(polygon
			(pts
				(xy 157.791658 -235.876338) (xy 159.823658 -235.876338) (xy 160.280858 -235.876338) (xy 160.280858 -236.991906)
				(xy 157.290516 -236.991906) (xy 157.290516 -235.876338)
			)
		)
	)
	(zone
		(layer "F.Cu")
		(hatch none 0.5)
		(connect_pads
			(clearance 0)
		)
		(min_thickness 0.25)
		(keepout
			(tracks allowed)
			(vias allowed)
			(pads allowed)
			(copperpour allowed)
			(footprints allowed)
		)
		(placement
			(enabled no)
			(sheetname "")
		)
		(fill
			(thermal_gap 0.5)
			(thermal_bridge_width 0.5)
			(island_removal_mode 0)
		)
		(polygon
			(pts
				(xy 44.735242 -224.316544) (xy 44.735242 -223.872806) (xy 47.060358 -223.872806) (xy 47.060358 -224.316544)
			)
		)
	)
	(zone
		(layer "F.Cu")
		(hatch none 0.5)
		(connect_pads
			(clearance 0)
		)
		(min_thickness 0.25)
		(keepout
			(tracks allowed)
			(vias allowed)
			(pads allowed)
			(copperpour allowed)
			(footprints allowed)
		)
		(placement
			(enabled no)
			(sheetname "")
		)
		(fill
			(thermal_gap 0.5)
			(thermal_bridge_width 0.5)
			(island_removal_mode 0)
		)
		(polygon
			(pts
				(xy 428.98822 -18.55978) (xy 428.98822 -15.425166) (xy 430.766982 -15.425166) (xy 430.766982 -18.55978)
			)
		)
	)
	(zone
		(layer "F.Cu")
		(hatch none 0.5)
		(connect_pads
			(clearance 0)
		)
		(min_thickness 0.25)
		(keepout
			(tracks allowed)
			(vias allowed)
			(pads allowed)
			(copperpour allowed)
			(footprints allowed)
		)
		(placement
			(enabled no)
			(sheetname "")
		)
		(fill
			(thermal_gap 0.5)
			(thermal_bridge_width 0.5)
			(island_removal_mode 0)
		)
		(polygon
			(pts
				(xy 384.35026 -217.668348) (xy 384.63728 -217.668348) (xy 384.66776 -217.637868) (xy 384.66776 -217.010488)
				(xy 384.5814 -216.924128) (xy 384.39344 -216.924128) (xy 384.31978 -216.997788) (xy 384.31978 -217.637868)
			)
		)
	)
	(zone
		(layer "F.Cu")
		(hatch none 0.5)
		(connect_pads
			(clearance 0)
		)
		(min_thickness 0.25)
		(keepout
			(tracks not_allowed)
			(vias allowed)
			(pads allowed)
			(copperpour not_allowed)
			(footprints allowed)
		)
		(placement
			(enabled no)
			(sheetname "")
		)
		(fill
			(thermal_gap 0.5)
			(thermal_bridge_width 0.5)
			(island_removal_mode 0)
		)
		(polygon
			(pts
				(arc
					(start 447.20002 -435.600094)
					(mid 448.799966 -434.000148)
					(end 450.399912 -435.600094)
				)
				(arc
					(start 450.399912 -435.600094)
					(mid 448.799966 -437.20004)
					(end 447.20002 -435.600094)
				)
			)
		)
	)
	(zone
		(layer "F.Cu")
		(hatch none 0.5)
		(connect_pads
			(clearance 0)
		)
		(min_thickness 0.25)
		(keepout
			(tracks allowed)
			(vias allowed)
			(pads allowed)
			(copperpour allowed)
			(footprints not_allowed)
		)
		(placement
			(enabled no)
			(sheetname "")
		)
		(fill
			(thermal_gap 0.5)
			(thermal_bridge_width 0.5)
			(island_removal_mode 0)
		)
		(polygon
			(pts
				(arc
					(start 462.000092 -22.29993)
					(mid 464.800188 -19.499834)
					(end 467.60003 -22.29993)
				)
				(arc
					(start 467.60003 -22.29993)
					(mid 464.800188 -25.099772)
					(end 462.000092 -22.29993)
				)
			)
		)
	)
	(zone
		(layer "F.Cu")
		(hatch none 0.5)
		(connect_pads
			(clearance 0)
		)
		(min_thickness 0.25)
		(keepout
			(tracks allowed)
			(vias allowed)
			(pads allowed)
			(copperpour allowed)
			(footprints allowed)
		)
		(placement
			(enabled no)
			(sheetname "")
		)
		(fill
			(thermal_gap 0.5)
			(thermal_bridge_width 0.5)
			(island_removal_mode 0)
		)
		(polygon
			(pts
				(xy 443.450726 -302.405034) (xy 443.450726 -302.176434) (xy 445.482726 -302.176434) (xy 445.482726 -302.405034)
			)
		)
	)
	(zone
		(layer "F.Cu")
		(hatch none 0.5)
		(connect_pads
			(clearance 0)
		)
		(min_thickness 0.25)
		(keepout
			(tracks allowed)
			(vias allowed)
			(pads allowed)
			(copperpour allowed)
			(footprints allowed)
		)
		(placement
			(enabled no)
			(sheetname "")
		)
		(fill
			(thermal_gap 0.5)
			(thermal_bridge_width 0.5)
			(island_removal_mode 0)
		)
		(polygon
			(pts
				(xy 58.058812 -410.948886) (xy 58.058812 -406.105868) (xy 59.943238 -406.105868) (xy 59.943238 -410.948886)
			)
		)
	)
	(zone
		(layer "F.Cu")
		(hatch none 0.5)
		(connect_pads
			(clearance 0)
		)
		(min_thickness 0.25)
		(keepout
			(tracks allowed)
			(vias allowed)
			(pads allowed)
			(copperpour allowed)
			(footprints allowed)
		)
		(placement
			(enabled no)
			(sheetname "")
		)
		(fill
			(thermal_gap 0.5)
			(thermal_bridge_width 0.5)
			(island_removal_mode 0)
		)
		(polygon
			(pts
				(xy 262.50011 -233.666538) (xy 262.50011 -233.2228) (xy 264.825226 -233.2228) (xy 264.825226 -233.666538)
			)
		)
	)
	(zone
		(layer "F.Cu")
		(hatch none 0.5)
		(connect_pads
			(clearance 0)
		)
		(min_thickness 0.25)
		(keepout
			(tracks allowed)
			(vias allowed)
			(pads allowed)
			(copperpour allowed)
			(footprints allowed)
		)
		(placement
			(enabled no)
			(sheetname "")
		)
		(fill
			(thermal_gap 0.5)
			(thermal_bridge_width 0.5)
			(island_removal_mode 0)
		)
		(polygon
			(pts
				(xy 157.791658 -265.004804) (xy 157.791658 -264.776204) (xy 159.823658 -264.776204) (xy 159.823658 -265.004804)
			)
		)
	)
	(zone
		(layer "F.Cu")
		(hatch none 0.5)
		(connect_pads
			(clearance 0)
		)
		(min_thickness 0.25)
		(keepout
			(tracks allowed)
			(vias allowed)
			(pads allowed)
			(copperpour allowed)
			(footprints allowed)
		)
		(placement
			(enabled no)
			(sheetname "")
		)
		(fill
			(thermal_gap 0.5)
			(thermal_bridge_width 0.5)
			(island_removal_mode 0)
		)
		(polygon
			(pts
				(xy 176.979326 -231.62641) (xy 179.011326 -231.62641) (xy 179.011326 -231.85501) (xy 176.979326 -231.85501)
				(xy 176.843182 -231.85501) (xy 176.796192 -231.85501) (xy 176.796192 -231.62641) (xy 176.843182 -231.62641)
			)
		)
	)
	(zone
		(layer "F.Cu")
		(hatch none 0.5)
		(connect_pads
			(clearance 0)
		)
		(min_thickness 0.25)
		(keepout
			(tracks allowed)
			(vias allowed)
			(pads allowed)
			(copperpour allowed)
			(footprints allowed)
		)
		(placement
			(enabled no)
			(sheetname "")
		)
		(fill
			(thermal_gap 0.5)
			(thermal_bridge_width 0.5)
			(island_removal_mode 0)
		)
		(polygon
			(pts
				(xy 176.979326 -280.076402) (xy 179.011326 -280.076402) (xy 179.011326 -280.305002) (xy 176.979326 -280.305002)
				(xy 176.843182 -280.305002) (xy 176.796192 -280.305002) (xy 176.796192 -280.076402) (xy 176.843182 -280.076402)
			)
		)
	)
	(zone
		(layer "F.Cu")
		(hatch none 0.5)
		(connect_pads
			(clearance 0)
		)
		(min_thickness 0.25)
		(keepout
			(tracks allowed)
			(vias allowed)
			(pads allowed)
			(copperpour allowed)
			(footprints allowed)
		)
		(placement
			(enabled no)
			(sheetname "")
		)
		(fill
			(thermal_gap 0.5)
			(thermal_bridge_width 0.5)
			(island_removal_mode 0)
		)
		(polygon
			(pts
				(xy 307.76291 -199.666606) (xy 307.76291 -199.222868) (xy 310.088026 -199.222868) (xy 310.088026 -199.666606)
			)
		)
	)
	(zone
		(layer "F.Cu")
		(hatch none 0.5)
		(connect_pads
			(clearance 0)
		)
		(min_thickness 0.25)
		(keepout
			(tracks allowed)
			(vias allowed)
			(pads allowed)
			(copperpour allowed)
			(footprints allowed)
		)
		(placement
			(enabled no)
			(sheetname "")
		)
		(fill
			(thermal_gap 0.5)
			(thermal_bridge_width 0.5)
			(island_removal_mode 0)
		)
		(polygon
			(pts
				(xy 424.919394 -214.626444) (xy 426.951394 -214.626444) (xy 426.951394 -214.855044) (xy 424.919394 -214.855044)
				(xy 424.78325 -214.855044) (xy 424.73626 -214.855044) (xy 424.73626 -214.626444) (xy 424.78325 -214.626444)
			)
		)
	)
	(zone
		(layer "F.Cu")
		(hatch none 0.5)
		(connect_pads
			(clearance 0)
		)
		(min_thickness 0.25)
		(keepout
			(tracks allowed)
			(vias allowed)
			(pads allowed)
			(copperpour allowed)
			(footprints not_allowed)
		)
		(placement
			(enabled no)
			(sheetname "")
		)
		(fill
			(thermal_gap 0.5)
			(thermal_bridge_width 0.5)
			(island_removal_mode 0)
		)
		(polygon
			(pts
				(xy 226.44989 -46.999906) (xy 230.300022 -46.999906) (xy 230.300022 -63.524892) (xy 238.300006 -63.524892)
				(xy 238.300006 -41.924986) (xy 242.149884 -41.924986) (xy 242.149884 -36.924996) (xy 237.949994 -36.924996)
				(xy 237.949994 -37.595048) (xy 230.300022 -37.595048) (xy 230.300022 -41.999916) (xy 226.44989 -41.999916)
			)
		)
	)
	(zone
		(layer "F.Cu")
		(hatch none 0.5)
		(connect_pads
			(clearance 0)
		)
		(min_thickness 0.25)
		(keepout
			(tracks allowed)
			(vias allowed)
			(pads allowed)
			(copperpour allowed)
			(footprints allowed)
		)
		(placement
			(enabled no)
			(sheetname "")
		)
		(fill
			(thermal_gap 0.5)
			(thermal_bridge_width 0.5)
			(island_removal_mode 0)
		)
		(polygon
			(pts
				(xy 59.822842 -265.116564) (xy 59.822842 -264.672826) (xy 62.147958 -264.672826) (xy 62.147958 -265.116564)
			)
		)
	)
	(zone
		(layer "F.Cu")
		(hatch none 0.5)
		(connect_pads
			(clearance 0)
		)
		(min_thickness 0.25)
		(keepout
			(tracks allowed)
			(vias allowed)
			(pads allowed)
			(copperpour allowed)
			(footprints allowed)
		)
		(placement
			(enabled no)
			(sheetname "")
		)
		(fill
			(thermal_gap 0.5)
			(thermal_bridge_width 0.5)
			(island_removal_mode 0)
		)
		(polygon
			(pts
				(xy 307.76291 -207.316578) (xy 307.76291 -206.87284) (xy 310.088026 -206.87284) (xy 310.088026 -207.316578)
			)
		)
	)
	(zone
		(layer "F.Cu")
		(hatch none 0.5)
		(connect_pads
			(clearance 0)
		)
		(min_thickness 0.25)
		(keepout
			(tracks allowed)
			(vias allowed)
			(pads allowed)
			(copperpour allowed)
			(footprints allowed)
		)
		(placement
			(enabled no)
			(sheetname "")
		)
		(fill
			(thermal_gap 0.5)
			(thermal_bridge_width 0.5)
			(island_removal_mode 0)
		)
		(polygon
			(pts
				(xy 324.965822 -404.802594) (xy 324.965822 -399.959576) (xy 326.850248 -399.959576) (xy 326.850248 -404.802594)
			)
		)
	)
	(zone
		(layer "F.Cu")
		(hatch none 0.5)
		(connect_pads
			(clearance 0)
		)
		(min_thickness 0.25)
		(keepout
			(tracks allowed)
			(vias allowed)
			(pads allowed)
			(copperpour allowed)
			(footprints allowed)
		)
		(placement
			(enabled no)
			(sheetname "")
		)
		(fill
			(thermal_gap 0.5)
			(thermal_bridge_width 0.5)
			(island_removal_mode 0)
		)
		(polygon
			(pts
				(xy 56.37911 -249.81662) (xy 56.37911 -249.372882) (xy 58.704226 -249.372882) (xy 58.704226 -249.81662)
			)
		)
	)
	(zone
		(layer "F.Cu")
		(hatch none 0.5)
		(connect_pads
			(clearance 0)
		)
		(min_thickness 0.25)
		(keepout
			(tracks not_allowed)
			(vias allowed)
			(pads allowed)
			(copperpour not_allowed)
			(footprints allowed)
		)
		(placement
			(enabled no)
			(sheetname "")
		)
		(fill
			(thermal_gap 0.5)
			(thermal_bridge_width 0.5)
			(island_removal_mode 0)
		)
		(polygon
			(pts
				(arc
					(start 4.19989 -22.29993)
					(mid 6.999986 -19.499834)
					(end 9.800082 -22.29993)
				)
				(arc
					(start 9.800082 -22.29993)
					(mid 6.999986 -25.100026)
					(end 4.19989 -22.29993)
				)
			)
		)
	)
	(zone
		(layer "F.Cu")
		(hatch none 0.5)
		(connect_pads
			(clearance 0)
		)
		(min_thickness 0.25)
		(keepout
			(tracks allowed)
			(vias allowed)
			(pads allowed)
			(copperpour allowed)
			(footprints allowed)
		)
		(placement
			(enabled no)
			(sheetname "")
		)
		(fill
			(thermal_gap 0.5)
			(thermal_bridge_width 0.5)
			(island_removal_mode 0)
		)
		(polygon
			(pts
				(xy 409.831794 -260.754876) (xy 409.831794 -260.526276) (xy 411.863794 -260.526276) (xy 411.863794 -260.754876)
			)
		)
	)
	(zone
		(layer "F.Cu")
		(hatch none 0.5)
		(connect_pads
			(clearance 0)
		)
		(min_thickness 0.25)
		(keepout
			(tracks allowed)
			(vias allowed)
			(pads allowed)
			(copperpour allowed)
			(footprints not_allowed)
		)
		(placement
			(enabled no)
			(sheetname "")
		)
		(fill
			(thermal_gap 0.5)
			(thermal_bridge_width 0.5)
			(island_removal_mode 0)
		)
		(polygon
			(pts
				(xy 123.916948 -42.049954) (xy 110.916974 -42.049954) (xy 110.916974 -52.049934) (xy 123.916948 -52.049934)
			)
		)
	)
	(zone
		(layer "F.Cu")
		(hatch none 0.5)
		(connect_pads
			(clearance 0)
		)
		(min_thickness 0.25)
		(keepout
			(tracks allowed)
			(vias allowed)
			(pads allowed)
			(copperpour allowed)
			(footprints allowed)
		)
		(placement
			(enabled no)
			(sheetname "")
		)
		(fill
			(thermal_gap 0.5)
			(thermal_bridge_width 0.5)
			(island_removal_mode 0)
		)
		(polygon
			(pts
				(xy 428.363126 -264.15492) (xy 428.363126 -263.92632) (xy 430.395126 -263.92632) (xy 430.395126 -264.15492)
			)
		)
	)
	(zone
		(layer "F.Cu")
		(hatch none 0.5)
		(connect_pads
			(clearance 0)
		)
		(min_thickness 0.25)
		(keepout
			(tracks allowed)
			(vias allowed)
			(pads allowed)
			(copperpour allowed)
			(footprints allowed)
		)
		(placement
			(enabled no)
			(sheetname "")
		)
		(fill
			(thermal_gap 0.5)
			(thermal_bridge_width 0.5)
			(island_removal_mode 0)
		)
		(polygon
			(pts
				(xy 428.363126 -236.104938) (xy 428.363126 -235.876338) (xy 430.395126 -235.876338) (xy 430.395126 -236.104938)
			)
		)
	)
	(zone
		(layer "F.Cu")
		(hatch none 0.5)
		(connect_pads
			(clearance 0)
		)
		(min_thickness 0.25)
		(keepout
			(tracks allowed)
			(vias allowed)
			(pads allowed)
			(copperpour allowed)
			(footprints allowed)
		)
		(placement
			(enabled no)
			(sheetname "")
		)
		(fill
			(thermal_gap 0.5)
			(thermal_bridge_width 0.5)
			(island_removal_mode 0)
		)
		(polygon
			(pts
				(xy 443.450726 -308.354984) (xy 443.450726 -308.126384) (xy 445.482726 -308.126384) (xy 445.482726 -308.354984)
			)
		)
	)
	(zone
		(layer "F.Cu")
		(hatch none 0.5)
		(connect_pads
			(clearance 0)
		)
		(min_thickness 0.25)
		(keepout
			(tracks allowed)
			(vias allowed)
			(pads allowed)
			(copperpour allowed)
			(footprints allowed)
		)
		(placement
			(enabled no)
			(sheetname "")
		)
		(fill
			(thermal_gap 0.5)
			(thermal_bridge_width 0.5)
			(island_removal_mode 0)
		)
		(polygon
			(pts
				(xy 405.731726 -202.105006) (xy 405.731726 -201.876406) (xy 407.763726 -201.876406) (xy 407.763726 -202.105006)
			)
		)
	)
	(zone
		(layer "F.Cu")
		(hatch none 0.5)
		(connect_pads
			(clearance 0)
		)
		(min_thickness 0.25)
		(keepout
			(tracks allowed)
			(vias allowed)
			(pads allowed)
			(copperpour allowed)
			(footprints allowed)
		)
		(placement
			(enabled no)
			(sheetname "")
		)
		(fill
			(thermal_gap 0.5)
			(thermal_bridge_width 0.5)
			(island_removal_mode 0)
		)
		(polygon
			(pts
				(xy 165.335458 -196.154802) (xy 165.335458 -195.926202) (xy 167.367458 -195.926202) (xy 167.367458 -196.154802)
			)
		)
	)
	(zone
		(layer "F.Cu")
		(hatch none 0.5)
		(connect_pads
			(clearance 0)
		)
		(min_thickness 0.25)
		(keepout
			(tracks allowed)
			(vias allowed)
			(pads allowed)
			(copperpour allowed)
			(footprints allowed)
		)
		(placement
			(enabled no)
			(sheetname "")
		)
		(fill
			(thermal_gap 0.5)
			(thermal_bridge_width 0.5)
			(island_removal_mode 0)
		)
		(polygon
			(pts
				(xy 458.538326 -235.2548) (xy 458.538326 -235.0262) (xy 460.570326 -235.0262) (xy 460.570326 -235.2548)
			)
		)
	)
	(zone
		(layer "F.Cu")
		(hatch none 0.5)
		(connect_pads
			(clearance 0)
		)
		(min_thickness 0.25)
		(keepout
			(tracks allowed)
			(vias allowed)
			(pads allowed)
			(copperpour allowed)
			(footprints not_allowed)
		)
		(placement
			(enabled no)
			(sheetname "")
		)
		(fill
			(thermal_gap 0.5)
			(thermal_bridge_width 0.5)
			(island_removal_mode 0)
		)
		(polygon
			(pts
				(xy 108.119926 -262.115046) (xy 108.119926 -236.514894) (xy 103.519986 -236.514894) (xy 103.519986 -262.115046)
			)
		)
	)
	(zone
		(layer "F.Cu")
		(hatch none 0.5)
		(connect_pads
			(clearance 0)
		)
		(min_thickness 0.25)
		(keepout
			(tracks allowed)
			(vias allowed)
			(pads allowed)
			(copperpour allowed)
			(footprints allowed)
		)
		(placement
			(enabled no)
			(sheetname "")
		)
		(fill
			(thermal_gap 0.5)
			(thermal_bridge_width 0.5)
			(island_removal_mode 0)
		)
		(polygon
			(pts
				(xy 413.275526 -306.654962) (xy 413.275526 -306.426362) (xy 415.307526 -306.426362) (xy 415.307526 -306.654962)
			)
		)
	)
	(zone
		(layer "F.Cu")
		(hatch none 0.5)
		(connect_pads
			(clearance 0)
		)
		(min_thickness 0.25)
		(keepout
			(tracks allowed)
			(vias allowed)
			(pads allowed)
			(copperpour allowed)
			(footprints allowed)
		)
		(placement
			(enabled no)
			(sheetname "")
		)
		(fill
			(thermal_gap 0.5)
			(thermal_bridge_width 0.5)
			(island_removal_mode 0)
		)
		(polygon
			(pts
				(xy 443.450726 -283.704792) (xy 443.450726 -283.476192) (xy 445.482726 -283.476192) (xy 445.482726 -283.704792)
			)
		)
	)
	(zone
		(layer "F.Cu")
		(hatch none 0.5)
		(connect_pads
			(clearance 0)
		)
		(min_thickness 0.25)
		(keepout
			(tracks allowed)
			(vias allowed)
			(pads allowed)
			(copperpour allowed)
			(footprints allowed)
		)
		(placement
			(enabled no)
			(sheetname "")
		)
		(fill
			(thermal_gap 0.5)
			(thermal_bridge_width 0.5)
			(island_removal_mode 0)
		)
		(polygon
			(pts
				(xy 262.50011 -281.266646) (xy 262.50011 -280.822908) (xy 264.825226 -280.822908) (xy 264.825226 -281.266646)
			)
		)
	)
	(zone
		(layer "F.Cu")
		(hatch none 0.5)
		(connect_pads
			(clearance 0)
		)
		(min_thickness 0.25)
		(keepout
			(tracks allowed)
			(vias allowed)
			(pads allowed)
			(copperpour allowed)
			(footprints allowed)
		)
		(placement
			(enabled no)
			(sheetname "")
		)
		(fill
			(thermal_gap 0.5)
			(thermal_bridge_width 0.5)
			(island_removal_mode 0)
		)
		(polygon
			(pts
				(xy 307.76291 -292.316662) (xy 307.76291 -291.872924) (xy 310.088026 -291.872924) (xy 310.088026 -292.316662)
			)
		)
	)
	(zone
		(layer "F.Cu")
		(hatch none 0.5)
		(connect_pads
			(clearance 0)
		)
		(min_thickness 0.25)
		(keepout
			(tracks allowed)
			(vias allowed)
			(pads allowed)
			(copperpour allowed)
			(footprints allowed)
		)
		(placement
			(enabled no)
			(sheetname "")
		)
		(fill
			(thermal_gap 0.5)
			(thermal_bridge_width 0.5)
			(island_removal_mode 0)
		)
		(polygon
			(pts
				(xy 458.538326 -283.704792) (xy 458.538326 -283.476192) (xy 460.570326 -283.476192) (xy 460.570326 -283.704792)
			)
		)
	)
	(zone
		(layer "F.Cu")
		(hatch none 0.5)
		(connect_pads
			(clearance 0)
		)
		(min_thickness 0.25)
		(keepout
			(tracks allowed)
			(vias allowed)
			(pads allowed)
			(copperpour allowed)
			(footprints not_allowed)
		)
		(placement
			(enabled no)
			(sheetname "")
		)
		(fill
			(thermal_gap 0.5)
			(thermal_bridge_width 0.5)
			(island_removal_mode 0)
		)
		(polygon
			(pts
				(xy 461.199992 -428.885096) (xy 461.199992 -401.385024) (xy 438.69991 -401.385024) (xy 438.69991 -428.885096)
			)
		)
	)
	(zone
		(layer "F.Cu")
		(hatch none 0.5)
		(connect_pads
			(clearance 0)
		)
		(min_thickness 0.25)
		(keepout
			(tracks allowed)
			(vias allowed)
			(pads allowed)
			(copperpour allowed)
			(footprints allowed)
		)
		(placement
			(enabled no)
			(sheetname "")
		)
		(fill
			(thermal_gap 0.5)
			(thermal_bridge_width 0.5)
			(island_removal_mode 0)
		)
		(polygon
			(pts
				(xy 409.831794 -303.026318) (xy 411.863794 -303.026318) (xy 411.863794 -303.254918) (xy 411.863794 -304.097944)
				(xy 409.633928 -304.097944) (xy 409.633928 -303.026318)
			)
		)
	)
	(zone
		(layer "F.Cu")
		(hatch none 0.5)
		(connect_pads
			(clearance 0)
		)
		(min_thickness 0.25)
		(keepout
			(tracks allowed)
			(vias allowed)
			(pads allowed)
			(copperpour allowed)
			(footprints allowed)
		)
		(placement
			(enabled no)
			(sheetname "")
		)
		(fill
			(thermal_gap 0.5)
			(thermal_bridge_width 0.5)
			(island_removal_mode 0)
		)
		(polygon
			(pts
				(xy 262.50011 -277.866602) (xy 262.50011 -277.422864) (xy 264.825226 -277.422864) (xy 264.825226 -277.866602)
			)
		)
	)
	(zone
		(layer "F.Cu")
		(hatch none 0.5)
		(connect_pads
			(clearance 0)
		)
		(min_thickness 0.25)
		(keepout
			(tracks allowed)
			(vias allowed)
			(pads allowed)
			(copperpour allowed)
			(footprints allowed)
		)
		(placement
			(enabled no)
			(sheetname "")
		)
		(fill
			(thermal_gap 0.5)
			(thermal_bridge_width 0.5)
			(island_removal_mode 0)
		)
		(polygon
			(pts
				(xy 63.951612 -282.116022) (xy 63.951612 -281.672284) (xy 66.161412 -281.672284) (xy 66.161412 -282.116022)
			)
		)
	)
	(zone
		(layer "F.Cu")
		(hatch none 0.5)
		(connect_pads
			(clearance 0)
		)
		(min_thickness 0.25)
		(keepout
			(tracks not_allowed)
			(vias allowed)
			(pads allowed)
			(copperpour not_allowed)
			(footprints allowed)
		)
		(placement
			(enabled no)
			(sheetname "")
		)
		(fill
			(thermal_gap 0.5)
			(thermal_bridge_width 0.5)
			(island_removal_mode 0)
		)
		(polygon
			(pts
				(arc
					(start 288.550096 -435.600094)
					(mid 293.550086 -430.600104)
					(end 298.550076 -435.600094)
				)
				(arc
					(start 298.550076 -435.600094)
					(mid 293.550086 -440.600084)
					(end 288.550096 -435.600094)
				)
			)
		)
	)
	(zone
		(layer "F.Cu")
		(hatch none 0.5)
		(connect_pads
			(clearance 0)
		)
		(min_thickness 0.25)
		(keepout
			(tracks allowed)
			(vias allowed)
			(pads allowed)
			(copperpour allowed)
			(footprints allowed)
		)
		(placement
			(enabled no)
			(sheetname "")
		)
		(fill
			(thermal_gap 0.5)
			(thermal_bridge_width 0.5)
			(island_removal_mode 0)
		)
		(polygon
			(pts
				(xy 161.891726 -282.005024) (xy 161.891726 -281.776424) (xy 163.923726 -281.776424) (xy 163.923726 -282.005024)
			)
		)
	)
	(zone
		(layer "F.Cu")
		(hatch none 0.5)
		(connect_pads
			(clearance 0)
		)
		(min_thickness 0.25)
		(keepout
			(tracks allowed)
			(vias allowed)
			(pads allowed)
			(copperpour allowed)
			(footprints allowed)
		)
		(placement
			(enabled no)
			(sheetname "")
		)
		(fill
			(thermal_gap 0.5)
			(thermal_bridge_width 0.5)
			(island_removal_mode 0)
		)
		(polygon
			(pts
				(xy 232.35412 -252.042168) (xy 232.35412 -248.869708) (xy 233.98226 -248.869708) (xy 233.98226 -252.042168)
			)
		)
	)
	(zone
		(layer "F.Cu")
		(hatch none 0.5)
		(connect_pads
			(clearance 0)
		)
		(min_thickness 0.25)
		(keepout
			(tracks allowed)
			(vias allowed)
			(pads allowed)
			(copperpour allowed)
			(footprints allowed)
		)
		(placement
			(enabled no)
			(sheetname "")
		)
		(fill
			(thermal_gap 0.5)
			(thermal_bridge_width 0.5)
			(island_removal_mode 0)
		)
		(polygon
			(pts
				(xy 405.731726 -250.554998) (xy 405.731726 -250.326398) (xy 407.763726 -250.326398) (xy 407.763726 -250.554998)
			)
		)
	)
	(zone
		(layer "F.Cu")
		(hatch none 0.5)
		(connect_pads
			(clearance 0)
		)
		(min_thickness 0.25)
		(keepout
			(tracks allowed)
			(vias allowed)
			(pads allowed)
			(copperpour allowed)
			(footprints allowed)
		)
		(placement
			(enabled no)
			(sheetname "")
		)
		(fill
			(thermal_gap 0.5)
			(thermal_bridge_width 0.5)
			(island_removal_mode 0)
		)
		(polygon
			(pts
				(xy 259.056378 -303.366424) (xy 259.056378 -302.922686) (xy 261.381494 -302.922686) (xy 261.381494 -303.366424)
			)
		)
	)
	(zone
		(layer "F.Cu")
		(hatch none 0.5)
		(connect_pads
			(clearance 0)
		)
		(min_thickness 0.25)
		(keepout
			(tracks allowed)
			(vias allowed)
			(pads allowed)
			(copperpour allowed)
			(footprints allowed)
		)
		(placement
			(enabled no)
			(sheetname "")
		)
		(fill
			(thermal_gap 0.5)
			(thermal_bridge_width 0.5)
			(island_removal_mode 0)
		)
		(polygon
			(pts
				(xy 413.22752 -367.251488) (xy 413.22752 -364.645448) (xy 419.05936 -364.645448) (xy 419.05936 -367.251488)
			)
		)
	)
	(zone
		(layer "F.Cu")
		(hatch none 0.5)
		(connect_pads
			(clearance 0)
		)
		(min_thickness 0.25)
		(keepout
			(tracks allowed)
			(vias allowed)
			(pads allowed)
			(copperpour allowed)
			(footprints allowed)
		)
		(placement
			(enabled no)
			(sheetname "")
		)
		(fill
			(thermal_gap 0.5)
			(thermal_bridge_width 0.5)
			(island_removal_mode 0)
		)
		(polygon
			(pts
				(xy 94.817692 -410.948886) (xy 94.817692 -406.105868) (xy 96.702118 -406.105868) (xy 96.702118 -410.948886)
			)
		)
	)
	(zone
		(layer "F.Cu")
		(hatch none 0.5)
		(connect_pads
			(clearance 0)
		)
		(min_thickness 0.25)
		(keepout
			(tracks allowed)
			(vias allowed)
			(pads allowed)
			(copperpour allowed)
			(footprints allowed)
		)
		(placement
			(enabled no)
			(sheetname "")
		)
		(fill
			(thermal_gap 0.5)
			(thermal_bridge_width 0.5)
			(island_removal_mode 0)
		)
		(polygon
			(pts
				(xy 413.275526 -265.854942) (xy 413.275526 -265.626342) (xy 415.307526 -265.626342) (xy 415.307526 -265.854942)
			)
		)
	)
	(zone
		(layer "F.Cu")
		(hatch none 0.5)
		(connect_pads
			(clearance 0)
		)
		(min_thickness 0.25)
		(keepout
			(tracks allowed)
			(vias allowed)
			(pads allowed)
			(copperpour allowed)
			(footprints not_allowed)
		)
		(placement
			(enabled no)
			(sheetname "")
		)
		(fill
			(thermal_gap 0.5)
			(thermal_bridge_width 0.5)
			(island_removal_mode 0)
		)
		(polygon
			(pts
				(arc
					(start 77.914754 -353.525074)
					(mid 81.914746 -349.525082)
					(end 85.914738 -353.525074)
				)
				(arc
					(start 85.914738 -353.525074)
					(mid 81.914746 -357.525066)
					(end 77.914754 -353.525074)
				)
			)
		)
	)
	(zone
		(layer "F.Cu")
		(hatch none 0.5)
		(connect_pads
			(clearance 0)
		)
		(min_thickness 0.25)
		(keepout
			(tracks allowed)
			(vias allowed)
			(pads allowed)
			(copperpour allowed)
			(footprints allowed)
		)
		(placement
			(enabled no)
			(sheetname "")
		)
		(fill
			(thermal_gap 0.5)
			(thermal_bridge_width 0.5)
			(island_removal_mode 0)
		)
		(polygon
			(pts
				(xy 176.979326 -312.606944) (xy 179.011326 -312.606944) (xy 179.011326 -312.378344) (xy 176.979326 -312.378344)
				(xy 176.848008 -312.378344) (xy 176.8221 -312.378344) (xy 176.8221 -312.606944) (xy 176.848008 -312.606944)
			)
		)
	)
	(zone
		(layer "F.Cu")
		(hatch none 0.5)
		(connect_pads
			(clearance 0)
		)
		(min_thickness 0.25)
		(keepout
			(tracks allowed)
			(vias allowed)
			(pads allowed)
			(copperpour allowed)
			(footprints allowed)
		)
		(placement
			(enabled no)
			(sheetname "")
		)
		(fill
			(thermal_gap 0.5)
			(thermal_bridge_width 0.5)
			(island_removal_mode 0)
		)
		(polygon
			(pts
				(xy 413.275526 -262.454898) (xy 413.275526 -262.226298) (xy 415.307526 -262.226298) (xy 415.307526 -262.454898)
			)
		)
	)
	(zone
		(layer "F.Cu")
		(hatch none 0.5)
		(connect_pads
			(clearance 0)
		)
		(min_thickness 0.25)
		(keepout
			(tracks allowed)
			(vias allowed)
			(pads allowed)
			(copperpour allowed)
			(footprints allowed)
		)
		(placement
			(enabled no)
			(sheetname "")
		)
		(fill
			(thermal_gap 0.5)
			(thermal_bridge_width 0.5)
			(island_removal_mode 0)
		)
		(polygon
			(pts
				(xy 277.58771 -225.166428) (xy 277.58771 -224.72269) (xy 279.912826 -224.72269) (xy 279.912826 -225.166428)
			)
		)
	)
	(zone
		(layer "F.Cu")
		(hatch none 0.5)
		(connect_pads
			(clearance 0)
		)
		(min_thickness 0.25)
		(keepout
			(tracks allowed)
			(vias allowed)
			(pads allowed)
			(copperpour allowed)
			(footprints allowed)
		)
		(placement
			(enabled no)
			(sheetname "")
		)
		(fill
			(thermal_gap 0.5)
			(thermal_bridge_width 0.5)
			(island_removal_mode 0)
		)
		(polygon
			(pts
				(xy 157.791658 -202.105006) (xy 157.791658 -201.876406) (xy 159.823658 -201.876406) (xy 159.823658 -202.105006)
			)
		)
	)
	(zone
		(layer "F.Cu")
		(hatch none 0.5)
		(connect_pads
			(clearance 0)
		)
		(min_thickness 0.25)
		(keepout
			(tracks allowed)
			(vias allowed)
			(pads allowed)
			(copperpour allowed)
			(footprints allowed)
		)
		(placement
			(enabled no)
			(sheetname "")
		)
		(fill
			(thermal_gap 0.5)
			(thermal_bridge_width 0.5)
			(island_removal_mode 0)
		)
		(polygon
			(pts
				(xy 405.731726 -283.704792) (xy 405.731726 -283.476192) (xy 407.763726 -283.476192) (xy 407.763726 -283.704792)
			)
		)
	)
	(zone
		(layer "F.Cu")
		(hatch none 0.5)
		(connect_pads
			(clearance 0)
		)
		(min_thickness 0.25)
		(keepout
			(tracks not_allowed)
			(vias allowed)
			(pads allowed)
			(copperpour not_allowed)
			(footprints allowed)
		)
		(placement
			(enabled no)
			(sheetname "")
		)
		(fill
			(thermal_gap 0.5)
			(thermal_bridge_width 0.5)
			(island_removal_mode 0)
		)
		(polygon
			(pts
				(xy 414.116012 -363.684312) (xy 414.358328 -363.684312) (xy 414.358328 -362.851446) (xy 414.116012 -362.851446)
			)
		)
	)
	(zone
		(layer "F.Cu")
		(hatch none 0.5)
		(connect_pads
			(clearance 0)
		)
		(min_thickness 0.25)
		(keepout
			(tracks allowed)
			(vias allowed)
			(pads allowed)
			(copperpour allowed)
			(footprints allowed)
		)
		(placement
			(enabled no)
			(sheetname "")
		)
		(fill
			(thermal_gap 0.5)
			(thermal_bridge_width 0.5)
			(island_removal_mode 0)
		)
		(polygon
			(pts
				(xy 210.598258 -308.354984) (xy 210.598258 -308.126384) (xy 212.630258 -308.126384) (xy 212.630258 -308.354984)
			)
		)
	)
	(zone
		(layer "F.Cu")
		(hatch none 0.5)
		(connect_pads
			(clearance 0)
		)
		(min_thickness 0.25)
		(keepout
			(tracks allowed)
			(vias allowed)
			(pads allowed)
			(copperpour allowed)
			(footprints allowed)
		)
		(placement
			(enabled no)
			(sheetname "")
		)
		(fill
			(thermal_gap 0.5)
			(thermal_bridge_width 0.5)
			(island_removal_mode 0)
		)
		(polygon
			(pts
				(xy 311.89168 -282.116022) (xy 311.89168 -281.672284) (xy 314.10148 -281.672284) (xy 314.10148 -282.116022)
			)
		)
	)
	(zone
		(layer "F.Cu")
		(hatch none 0.5)
		(connect_pads
			(clearance 0)
		)
		(min_thickness 0.25)
		(keepout
			(tracks allowed)
			(vias allowed)
			(pads allowed)
			(copperpour allowed)
			(footprints allowed)
		)
		(placement
			(enabled no)
			(sheetname "")
		)
		(fill
			(thermal_gap 0.5)
			(thermal_bridge_width 0.5)
			(island_removal_mode 0)
		)
		(polygon
			(pts
				(xy 212.948012 -268.472412) (xy 212.948012 -268.956536) (xy 212.948012 -269.254986) (xy 212.630258 -269.254986)
				(xy 210.598258 -269.254986) (xy 210.28025 -269.254986) (xy 210.182714 -269.254986) (xy 210.182714 -268.356842)
				(xy 212.948012 -268.356842)
			)
		)
	)
	(zone
		(layer "F.Cu")
		(hatch none 0.5)
		(connect_pads
			(clearance 0)
		)
		(min_thickness 0.25)
		(keepout
			(tracks allowed)
			(vias allowed)
			(pads allowed)
			(copperpour allowed)
			(footprints allowed)
		)
		(placement
			(enabled no)
			(sheetname "")
		)
		(fill
			(thermal_gap 0.5)
			(thermal_bridge_width 0.5)
			(island_removal_mode 0)
		)
		(polygon
			(pts
				(xy 413.275526 -291.355018) (xy 413.275526 -291.126418) (xy 415.307526 -291.126418) (xy 415.307526 -291.355018)
			)
		)
	)
	(zone
		(layer "F.Cu")
		(hatch none 0.5)
		(connect_pads
			(clearance 0)
		)
		(min_thickness 0.25)
		(keepout
			(tracks allowed)
			(vias allowed)
			(pads allowed)
			(copperpour allowed)
			(footprints allowed)
		)
		(placement
			(enabled no)
			(sheetname "")
		)
		(fill
			(thermal_gap 0.5)
			(thermal_bridge_width 0.5)
			(island_removal_mode 0)
		)
		(polygon
			(pts
				(xy 14.560042 -244.716554) (xy 14.560042 -244.272816) (xy 16.885158 -244.272816) (xy 16.885158 -244.716554)
			)
		)
	)
	(zone
		(layer "F.Cu")
		(hatch none 0.5)
		(connect_pads
			(clearance 0)
		)
		(min_thickness 0.25)
		(keepout
			(tracks allowed)
			(vias allowed)
			(pads allowed)
			(copperpour allowed)
			(footprints allowed)
		)
		(placement
			(enabled no)
			(sheetname "")
		)
		(fill
			(thermal_gap 0.5)
			(thermal_bridge_width 0.5)
			(island_removal_mode 0)
		)
		(polygon
			(pts
				(xy 262.50011 -299.966634) (xy 262.50011 -299.522896) (xy 264.825226 -299.522896) (xy 264.825226 -299.966634)
			)
		)
	)
	(zone
		(layer "F.Cu")
		(hatch none 0.5)
		(connect_pads
			(clearance 0)
		)
		(min_thickness 0.25)
		(keepout
			(tracks allowed)
			(vias allowed)
			(pads allowed)
			(copperpour allowed)
			(footprints allowed)
		)
		(placement
			(enabled no)
			(sheetname "")
		)
		(fill
			(thermal_gap 0.5)
			(thermal_bridge_width 0.5)
			(island_removal_mode 0)
		)
		(polygon
			(pts
				(xy 392.408664 -404.802594) (xy 392.408664 -399.959576) (xy 394.29309 -399.959576) (xy 394.29309 -404.802594)
			)
		)
	)
	(zone
		(layer "F.Cu")
		(hatch none 0.5)
		(connect_pads
			(clearance 0)
		)
		(min_thickness 0.25)
		(keepout
			(tracks allowed)
			(vias allowed)
			(pads allowed)
			(copperpour allowed)
			(footprints allowed)
		)
		(placement
			(enabled no)
			(sheetname "")
		)
		(fill
			(thermal_gap 0.5)
			(thermal_bridge_width 0.5)
			(island_removal_mode 0)
		)
		(polygon
			(pts
				(xy 30.98546 -5.939028) (xy 30.98546 -4.049268) (xy 33.0327 -4.049268) (xy 33.0327 -5.939028)
			)
		)
	)
	(zone
		(layer "F.Cu")
		(hatch none 0.5)
		(connect_pads
			(clearance 0)
		)
		(min_thickness 0.25)
		(keepout
			(tracks allowed)
			(vias allowed)
			(pads allowed)
			(copperpour allowed)
			(footprints allowed)
		)
		(placement
			(enabled no)
			(sheetname "")
		)
		(fill
			(thermal_gap 0.5)
			(thermal_bridge_width 0.5)
			(island_removal_mode 0)
		)
		(polygon
			(pts
				(xy 277.58771 -215.816434) (xy 277.58771 -215.372696) (xy 279.912826 -215.372696) (xy 279.912826 -215.816434)
			)
		)
	)
	(zone
		(layer "F.Cu")
		(hatch none 0.5)
		(connect_pads
			(clearance 0)
		)
		(min_thickness 0.25)
		(keepout
			(tracks not_allowed)
			(vias allowed)
			(pads allowed)
			(copperpour not_allowed)
			(footprints allowed)
		)
		(placement
			(enabled no)
			(sheetname "")
		)
		(fill
			(thermal_gap 0.5)
			(thermal_bridge_width 0.5)
			(island_removal_mode 0)
		)
		(polygon
			(pts
				(arc
					(start 447.199766 -435.59984)
					(mid 448.799966 -433.99964)
					(end 450.399912 -435.59984)
				)
				(arc
					(start 450.399912 -435.59984)
					(mid 448.799966 -437.199786)
					(end 447.199766 -435.59984)
				)
			)
		)
	)
	(zone
		(layer "F.Cu")
		(hatch none 0.5)
		(connect_pads
			(clearance 0)
		)
		(min_thickness 0.25)
		(keepout
			(tracks not_allowed)
			(vias allowed)
			(pads allowed)
			(copperpour not_allowed)
			(footprints allowed)
		)
		(placement
			(enabled no)
			(sheetname "")
		)
		(fill
			(thermal_gap 0.5)
			(thermal_bridge_width 0.5)
			(island_removal_mode 0)
		)
		(polygon
			(pts
				(arc
					(start 463.199988 -33.90011)
					(mid 464.75015 -35.450272)
					(end 466.300058 -33.90011)
				)
				(arc
					(start 466.300058 -32.29991)
					(mid 464.75015 -30.750002)
					(end 463.199988 -32.29991)
				)
			)
		)
	)
	(zone
		(layer "F.Cu")
		(hatch none 0.5)
		(connect_pads
			(clearance 0)
		)
		(min_thickness 0.25)
		(keepout
			(tracks allowed)
			(vias allowed)
			(pads allowed)
			(copperpour allowed)
			(footprints not_allowed)
		)
		(placement
			(enabled no)
			(sheetname "")
		)
		(fill
			(thermal_gap 0.5)
			(thermal_bridge_width 0.5)
			(island_removal_mode 0)
		)
		(polygon
			(pts
				(xy 285.25597 -330.091796) (xy 291.35578 -330.091796) (xy 291.35578 -186.09183) (xy 285.25597 -186.09183)
			)
		)
	)
	(zone
		(layer "F.Cu")
		(hatch none 0.5)
		(connect_pads
			(clearance 0)
		)
		(min_thickness 0.25)
		(keepout
			(tracks allowed)
			(vias allowed)
			(pads allowed)
			(copperpour allowed)
			(footprints allowed)
		)
		(placement
			(enabled no)
			(sheetname "")
		)
		(fill
			(thermal_gap 0.5)
			(thermal_bridge_width 0.5)
			(island_removal_mode 0)
		)
		(polygon
			(pts
				(xy 409.831794 -270.726408) (xy 411.863794 -270.726408) (xy 411.863794 -270.728694) (xy 412.04261 -270.728694)
				(xy 412.04261 -270.96593) (xy 412.180532 -270.96593) (xy 412.223712 -271.00911) (xy 412.223712 -271.141952)
				(xy 412.223712 -271.44599) (xy 412.151068 -271.518634) (xy 409.610814 -271.518634) (xy 409.46959 -271.37741)
				(xy 409.46959 -271.180306) (xy 409.551124 -271.098772) (xy 409.551124 -270.726408) (xy 409.64866 -270.726408)
				(xy 409.69565 -270.726408)
			)
		)
	)
	(zone
		(layer "F.Cu")
		(hatch none 0.5)
		(connect_pads
			(clearance 0)
		)
		(min_thickness 0.25)
		(keepout
			(tracks allowed)
			(vias allowed)
			(pads allowed)
			(copperpour allowed)
			(footprints allowed)
		)
		(placement
			(enabled no)
			(sheetname "")
		)
		(fill
			(thermal_gap 0.5)
			(thermal_bridge_width 0.5)
			(island_removal_mode 0)
		)
		(polygon
			(pts
				(xy 37.376862 -18.570702) (xy 37.376862 -15.436088) (xy 39.155624 -15.436088) (xy 39.155624 -18.570702)
			)
		)
	)
	(zone
		(layer "F.Cu")
		(hatch none 0.5)
		(connect_pads
			(clearance 0)
		)
		(min_thickness 0.25)
		(keepout
			(tracks allowed)
			(vias allowed)
			(pads allowed)
			(copperpour allowed)
			(footprints allowed)
		)
		(placement
			(enabled no)
			(sheetname "")
		)
		(fill
			(thermal_gap 0.5)
			(thermal_bridge_width 0.5)
			(island_removal_mode 0)
		)
		(polygon
			(pts
				(xy 273.993356 -319.243456) (xy 273.993356 -316.881256) (xy 276.609556 -316.881256) (xy 276.609556 -319.243456)
			)
		)
	)
	(zone
		(layer "F.Cu")
		(hatch none 0.5)
		(connect_pads
			(clearance 0)
		)
		(min_thickness 0.25)
		(keepout
			(tracks allowed)
			(vias allowed)
			(pads allowed)
			(copperpour allowed)
			(footprints allowed)
		)
		(placement
			(enabled no)
			(sheetname "")
		)
		(fill
			(thermal_gap 0.5)
			(thermal_bridge_width 0.5)
			(island_removal_mode 0)
		)
		(polygon
			(pts
				(xy 29.647642 -262.566658) (xy 29.647642 -262.12292) (xy 31.972758 -262.12292) (xy 31.972758 -262.566658)
			)
		)
	)
	(zone
		(layer "F.Cu")
		(hatch none 0.5)
		(connect_pads
			(clearance 0)
		)
		(min_thickness 0.25)
		(keepout
			(tracks allowed)
			(vias allowed)
			(pads allowed)
			(copperpour allowed)
			(footprints allowed)
		)
		(placement
			(enabled no)
			(sheetname "")
		)
		(fill
			(thermal_gap 0.5)
			(thermal_bridge_width 0.5)
			(island_removal_mode 0)
		)
		(polygon
			(pts
				(xy 440.006994 -261.376414) (xy 442.038994 -261.376414) (xy 442.038994 -261.605014) (xy 440.006994 -261.605014)
				(xy 439.84037 -261.605014) (xy 439.84037 -261.376414)
			)
		)
	)
	(zone
		(layer "F.Cu")
		(hatch none 0.5)
		(connect_pads
			(clearance 0)
		)
		(min_thickness 0.25)
		(keepout
			(tracks allowed)
			(vias allowed)
			(pads allowed)
			(copperpour allowed)
			(footprints allowed)
		)
		(placement
			(enabled no)
			(sheetname "")
		)
		(fill
			(thermal_gap 0.5)
			(thermal_bridge_width 0.5)
			(island_removal_mode 0)
		)
		(polygon
			(pts
				(xy 262.50011 -240.466626) (xy 262.50011 -240.022888) (xy 264.825226 -240.022888) (xy 264.825226 -240.466626)
			)
		)
	)
	(zone
		(layer "F.Cu")
		(hatch none 0.5)
		(connect_pads
			(clearance 0)
		)
		(min_thickness 0.25)
		(keepout
			(tracks not_allowed)
			(vias allowed)
			(pads allowed)
			(copperpour not_allowed)
			(footprints allowed)
		)
		(placement
			(enabled no)
			(sheetname "")
		)
		(fill
			(thermal_gap 0.5)
			(thermal_bridge_width 0.5)
			(island_removal_mode 0)
		)
		(polygon
			(pts
				(xy 94.953328 -336.26044) (xy 98.88982 -336.26044) (xy 98.88982 -336.225388) (xy 98.73996 -336.075528)
				(xy 97.341182 -336.075528) (xy 97.341182 -333.916528) (xy 99.497896 -333.916528) (xy 99.497896 -333.666846)
				(xy 97.1931 -333.666846) (xy 97.1931 -333.987648) (xy 97.049844 -333.987648) (xy 97.049844 -336.019902)
				(xy 95.195644 -336.019902) (xy 95.195644 -335.778856) (xy 94.953328 -335.778856)
			)
		)
	)
	(zone
		(layer "F.Cu")
		(hatch none 0.5)
		(connect_pads
			(clearance 0)
		)
		(min_thickness 0.25)
		(keepout
			(tracks allowed)
			(vias allowed)
			(pads allowed)
			(copperpour allowed)
			(footprints allowed)
		)
		(placement
			(enabled no)
			(sheetname "")
		)
		(fill
			(thermal_gap 0.5)
			(thermal_bridge_width 0.5)
			(island_removal_mode 0)
		)
		(polygon
			(pts
				(xy 131.35356 -18.537428) (xy 131.35356 -15.700248) (xy 142.89532 -15.700248) (xy 142.89532 -18.537428)
			)
		)
	)
	(zone
		(layer "F.Cu")
		(hatch none 0.5)
		(connect_pads
			(clearance 0)
		)
		(min_thickness 0.25)
		(keepout
			(tracks allowed)
			(vias allowed)
			(pads allowed)
			(copperpour allowed)
			(footprints allowed)
		)
		(placement
			(enabled no)
			(sheetname "")
		)
		(fill
			(thermal_gap 0.5)
			(thermal_bridge_width 0.5)
			(island_removal_mode 0)
		)
		(polygon
			(pts
				(xy 207.154526 -233.326432) (xy 209.186526 -233.326432) (xy 209.186526 -233.555032) (xy 207.154526 -233.555032)
				(xy 207.018382 -233.555032) (xy 206.971392 -233.555032) (xy 206.971392 -233.326432) (xy 207.018382 -233.326432)
			)
		)
	)
	(zone
		(layer "F.Cu")
		(hatch none 0.5)
		(connect_pads
			(clearance 0)
		)
		(min_thickness 0.25)
		(keepout
			(tracks allowed)
			(vias allowed)
			(pads allowed)
			(copperpour allowed)
			(footprints allowed)
		)
		(placement
			(enabled no)
			(sheetname "")
		)
		(fill
			(thermal_gap 0.5)
			(thermal_bridge_width 0.5)
			(island_removal_mode 0)
		)
		(polygon
			(pts
				(xy 355.736398 -333.586582) (xy 352.200718 -333.586582) (xy 352.200718 -331.503782) (xy 355.736398 -331.503782)
			)
		)
	)
	(zone
		(layer "F.Cu")
		(hatch none 0.5)
		(connect_pads
			(clearance 0)
		)
		(min_thickness 0.25)
		(keepout
			(tracks allowed)
			(vias allowed)
			(pads allowed)
			(copperpour allowed)
			(footprints allowed)
		)
		(placement
			(enabled no)
			(sheetname "")
		)
		(fill
			(thermal_gap 0.5)
			(thermal_bridge_width 0.5)
			(island_removal_mode 0)
		)
		(polygon
			(pts
				(xy 428.363126 -213.155022) (xy 428.363126 -212.926422) (xy 430.395126 -212.926422) (xy 430.395126 -213.155022)
			)
		)
	)
	(zone
		(layer "F.Cu")
		(hatch none 0.5)
		(connect_pads
			(clearance 0)
		)
		(min_thickness 0.25)
		(keepout
			(tracks allowed)
			(vias allowed)
			(pads allowed)
			(copperpour allowed)
			(footprints allowed)
		)
		(placement
			(enabled no)
			(sheetname "")
		)
		(fill
			(thermal_gap 0.5)
			(thermal_bridge_width 0.5)
			(island_removal_mode 0)
		)
		(polygon
			(pts
				(xy 289.231578 -209.866484) (xy 289.231578 -209.422746) (xy 291.556694 -209.422746) (xy 291.556694 -209.866484)
			)
		)
	)
	(zone
		(layer "F.Cu")
		(hatch none 0.5)
		(connect_pads
			(clearance 0)
		)
		(min_thickness 0.25)
		(keepout
			(tracks allowed)
			(vias allowed)
			(pads allowed)
			(copperpour allowed)
			(footprints allowed)
		)
		(placement
			(enabled no)
			(sheetname "")
		)
		(fill
			(thermal_gap 0.5)
			(thermal_bridge_width 0.5)
			(island_removal_mode 0)
		)
		(polygon
			(pts
				(xy 207.25892 -36.618926) (xy 207.25892 -32.953706) (xy 211.0232 -32.953706) (xy 211.0232 -36.618926)
			)
		)
	)
	(zone
		(layer "F.Cu")
		(hatch none 0.5)
		(connect_pads
			(clearance 0)
		)
		(min_thickness 0.25)
		(keepout
			(tracks allowed)
			(vias allowed)
			(pads allowed)
			(copperpour allowed)
			(footprints allowed)
		)
		(placement
			(enabled no)
			(sheetname "")
		)
		(fill
			(thermal_gap 0.5)
			(thermal_bridge_width 0.5)
			(island_removal_mode 0)
		)
		(polygon
			(pts
				(xy 11.11631 -230.266494) (xy 11.11631 -229.822756) (xy 13.441426 -229.822756) (xy 13.441426 -230.266494)
			)
		)
	)
	(zone
		(layer "F.Cu")
		(hatch none 0.5)
		(connect_pads
			(clearance 0)
		)
		(min_thickness 0.25)
		(keepout
			(tracks allowed)
			(vias allowed)
			(pads allowed)
			(copperpour allowed)
			(footprints allowed)
		)
		(placement
			(enabled no)
			(sheetname "")
		)
		(fill
			(thermal_gap 0.5)
			(thermal_bridge_width 0.5)
			(island_removal_mode 0)
		)
		(polygon
			(pts
				(xy 311.89168 -268.516608) (xy 311.89168 -268.07287) (xy 314.12688 -268.07287) (xy 314.35294 -268.07287)
				(xy 314.35294 -268.915642) (xy 311.89168 -268.915642)
			)
		)
	)
	(zone
		(layer "F.Cu")
		(hatch none 0.5)
		(connect_pads
			(clearance 0)
		)
		(min_thickness 0.25)
		(keepout
			(tracks allowed)
			(vias allowed)
			(pads allowed)
			(copperpour allowed)
			(footprints allowed)
		)
		(placement
			(enabled no)
			(sheetname "")
		)
		(fill
			(thermal_gap 0.5)
			(thermal_bridge_width 0.5)
			(island_removal_mode 0)
		)
		(polygon
			(pts
				(xy 199.352662 -319.243202) (xy 199.352662 -316.881002) (xy 201.968862 -316.881002) (xy 201.968862 -319.243202)
			)
		)
	)
	(zone
		(layer "F.Cu")
		(hatch none 0.5)
		(connect_pads
			(clearance 0)
		)
		(min_thickness 0.25)
		(keepout
			(tracks allowed)
			(vias allowed)
			(pads allowed)
			(copperpour allowed)
			(footprints allowed)
		)
		(placement
			(enabled no)
			(sheetname "")
		)
		(fill
			(thermal_gap 0.5)
			(thermal_bridge_width 0.5)
			(island_removal_mode 0)
		)
		(polygon
			(pts
				(xy 242.25504 -59.224926) (xy 242.25504 -56.885586) (xy 243.5733 -56.885586) (xy 243.5733 -59.224926)
			)
		)
	)
	(zone
		(layer "F.Cu")
		(hatch none 0.5)
		(connect_pads
			(clearance 0)
		)
		(min_thickness 0.25)
		(keepout
			(tracks allowed)
			(vias allowed)
			(pads allowed)
			(copperpour allowed)
			(footprints allowed)
		)
		(placement
			(enabled no)
			(sheetname "")
		)
		(fill
			(thermal_gap 0.5)
			(thermal_bridge_width 0.5)
			(island_removal_mode 0)
		)
		(polygon
			(pts
				(xy 304.319178 -263.416542) (xy 304.319178 -262.972804) (xy 306.644294 -262.972804) (xy 306.644294 -263.416542)
			)
		)
	)
	(zone
		(layer "F.Cu")
		(hatch none 0.5)
		(connect_pads
			(clearance 0)
		)
		(min_thickness 0.25)
		(keepout
			(tracks allowed)
			(vias allowed)
			(pads allowed)
			(copperpour allowed)
			(footprints allowed)
		)
		(placement
			(enabled no)
			(sheetname "")
		)
		(fill
			(thermal_gap 0.5)
			(thermal_bridge_width 0.5)
			(island_removal_mode 0)
		)
		(polygon
			(pts
				(xy 85.90026 -328.417428) (xy 85.90026 -330.109068) (xy 85.96376 -330.172568) (xy 94.67342 -330.172568)
				(xy 95.15856 -329.687428) (xy 95.15856 -328.018648) (xy 95.31604 -327.861168) (xy 123.32716 -327.861168)
				(xy 126.65964 -331.193648) (xy 131.34086 -331.193648) (xy 132.43814 -332.290928) (xy 132.43814 -333.451708)
				(xy 134.99084 -336.004408) (xy 139.92352 -336.004408) (xy 140.36802 -335.559908) (xy 140.36802 -335.095088)
				(xy 139.92606 -334.653128) (xy 136.31926 -334.653128) (xy 133.74624 -332.080108) (xy 133.74624 -330.540868)
				(xy 132.43814 -329.232768) (xy 128.72466 -329.232768) (xy 125.45568 -325.963788) (xy 93.90126 -325.963788)
				(xy 91.94038 -327.924668) (xy 86.39302 -327.924668)
			)
		)
	)
	(zone
		(layer "F.Cu")
		(hatch none 0.5)
		(connect_pads
			(clearance 0)
		)
		(min_thickness 0.25)
		(keepout
			(tracks allowed)
			(vias allowed)
			(pads allowed)
			(copperpour allowed)
			(footprints allowed)
		)
		(placement
			(enabled no)
			(sheetname "")
		)
		(fill
			(thermal_gap 0.5)
			(thermal_bridge_width 0.5)
			(island_removal_mode 0)
		)
		(polygon
			(pts
				(xy 415.880042 -168.18356) (xy 415.880042 -171.71924) (xy 413.797242 -171.71924) (xy 413.797242 -168.18356)
			)
		)
	)
	(zone
		(layer "F.Cu")
		(hatch none 0.5)
		(connect_pads
			(clearance 0)
		)
		(min_thickness 0.25)
		(keepout
			(tracks allowed)
			(vias allowed)
			(pads allowed)
			(copperpour allowed)
			(footprints allowed)
		)
		(placement
			(enabled no)
			(sheetname "")
		)
		(fill
			(thermal_gap 0.5)
			(thermal_bridge_width 0.5)
			(island_removal_mode 0)
		)
		(polygon
			(pts
				(xy 307.76291 -252.366526) (xy 307.76291 -251.922788) (xy 310.088026 -251.922788) (xy 310.088026 -252.366526)
			)
		)
	)
	(zone
		(layer "F.Cu")
		(hatch none 0.5)
		(connect_pads
			(clearance 0)
		)
		(min_thickness 0.25)
		(keepout
			(tracks allowed)
			(vias allowed)
			(pads allowed)
			(copperpour allowed)
			(footprints allowed)
		)
		(placement
			(enabled no)
			(sheetname "")
		)
		(fill
			(thermal_gap 0.5)
			(thermal_bridge_width 0.5)
			(island_removal_mode 0)
		)
		(polygon
			(pts
				(xy 311.91708 -213.266528) (xy 311.91708 -212.82279) (xy 314.12688 -212.82279) (xy 314.12688 -213.266528)
			)
		)
	)
	(zone
		(layer "F.Cu")
		(hatch none 0.5)
		(connect_pads
			(clearance 0)
		)
		(min_thickness 0.25)
		(keepout
			(tracks allowed)
			(vias allowed)
			(pads allowed)
			(copperpour allowed)
			(footprints allowed)
		)
		(placement
			(enabled no)
			(sheetname "")
		)
		(fill
			(thermal_gap 0.5)
			(thermal_bridge_width 0.5)
			(island_removal_mode 0)
		)
		(polygon
			(pts
				(xy 159.823658 -233.555032) (xy 157.791658 -233.555032) (xy 157.600396 -233.555032) (xy 157.600396 -232.817416)
				(xy 160.03143 -232.817416) (xy 160.03143 -233.555032)
			)
		)
	)
	(zone
		(layer "F.Cu")
		(hatch none 0.5)
		(connect_pads
			(clearance 0)
		)
		(min_thickness 0.25)
		(keepout
			(tracks allowed)
			(vias allowed)
			(pads allowed)
			(copperpour allowed)
			(footprints not_allowed)
		)
		(placement
			(enabled no)
			(sheetname "")
		)
		(fill
			(thermal_gap 0.5)
			(thermal_bridge_width 0.5)
			(island_removal_mode 0)
		)
		(polygon
			(pts
				(arc
					(start 199.64527 -51.999896)
					(mid 204.64526 -46.999906)
					(end 209.64525 -51.999896)
				)
				(arc
					(start 209.64525 -51.999896)
					(mid 204.64526 -56.999886)
					(end 199.64527 -51.999896)
				)
			)
		)
	)
	(zone
		(layer "F.Cu")
		(hatch none 0.5)
		(connect_pads
			(clearance 0)
		)
		(min_thickness 0.25)
		(keepout
			(tracks allowed)
			(vias allowed)
			(pads allowed)
			(copperpour allowed)
			(footprints allowed)
		)
		(placement
			(enabled no)
			(sheetname "")
		)
		(fill
			(thermal_gap 0.5)
			(thermal_bridge_width 0.5)
			(island_removal_mode 0)
		)
		(polygon
			(pts
				(xy 197.553834 -239.507014) (xy 195.521834 -239.507014) (xy 195.521834 -239.504728) (xy 195.343018 -239.504728)
				(xy 195.343018 -239.267492) (xy 195.205096 -239.267492) (xy 195.161916 -239.224312) (xy 195.161916 -239.09147)
				(xy 195.161916 -238.787432) (xy 195.23456 -238.714788) (xy 197.774814 -238.714788) (xy 197.916038 -238.856012)
				(xy 197.916038 -239.053116) (xy 197.834504 -239.13465) (xy 197.834504 -239.507014) (xy 197.736968 -239.507014)
				(xy 197.689978 -239.507014)
			)
		)
	)
	(zone
		(layer "F.Cu")
		(hatch none 0.5)
		(connect_pads
			(clearance 0)
		)
		(min_thickness 0.25)
		(keepout
			(tracks allowed)
			(vias allowed)
			(pads allowed)
			(copperpour allowed)
			(footprints allowed)
		)
		(placement
			(enabled no)
			(sheetname "")
		)
		(fill
			(thermal_gap 0.5)
			(thermal_bridge_width 0.5)
			(island_removal_mode 0)
		)
		(polygon
			(pts
				(xy 52.259992 -269.375128) (xy 52.259992 -268.93139) (xy 54.585108 -268.93139) (xy 54.585108 -269.375128)
			)
		)
	)
	(zone
		(layer "F.Cu")
		(hatch none 0.5)
		(connect_pads
			(clearance 0)
		)
		(min_thickness 0.25)
		(keepout
			(tracks allowed)
			(vias allowed)
			(pads allowed)
			(copperpour allowed)
			(footprints not_allowed)
		)
		(placement
			(enabled no)
			(sheetname "")
		)
		(fill
			(thermal_gap 0.5)
			(thermal_bridge_width 0.5)
			(island_removal_mode 0)
		)
		(polygon
			(pts
				(xy 391.788396 -70.65518) (xy 388.152894 -70.65518) (xy 388.152894 -43.344592) (xy 391.788396 -43.344592)
				(arc
					(start 391.788396 -41.999916)
					(mid 376.788172 -57.00014)
					(end 391.788396 -72.00011)
				)
			)
		)
	)
	(zone
		(layer "F.Cu")
		(hatch none 0.5)
		(connect_pads
			(clearance 0)
		)
		(min_thickness 0.25)
		(keepout
			(tracks not_allowed)
			(vias allowed)
			(pads allowed)
			(copperpour not_allowed)
			(footprints allowed)
		)
		(placement
			(enabled no)
			(sheetname "")
		)
		(fill
			(thermal_gap 0.5)
			(thermal_bridge_width 0.5)
			(island_removal_mode 0)
		)
		(polygon
			(pts
				(xy 103.11384 -335.346548) (xy 103.356156 -335.346548) (xy 103.356156 -334.348328) (xy 103.11384 -334.348328)
			)
		)
	)
	(zone
		(layer "F.Cu")
		(hatch none 0.5)
		(connect_pads
			(clearance 0)
		)
		(min_thickness 0.25)
		(keepout
			(tracks allowed)
			(vias allowed)
			(pads allowed)
			(copperpour allowed)
			(footprints allowed)
		)
		(placement
			(enabled no)
			(sheetname "")
		)
		(fill
			(thermal_gap 0.5)
			(thermal_bridge_width 0.5)
			(island_removal_mode 0)
		)
		(polygon
			(pts
				(xy 180.423058 -235.2548) (xy 180.423058 -235.0262) (xy 182.455058 -235.0262) (xy 182.455058 -235.2548)
			)
		)
	)
	(zone
		(layer "F.Cu")
		(hatch none 0.5)
		(connect_pads
			(clearance 0)
		)
		(min_thickness 0.25)
		(keepout
			(tracks allowed)
			(vias allowed)
			(pads allowed)
			(copperpour allowed)
			(footprints allowed)
		)
		(placement
			(enabled no)
			(sheetname "")
		)
		(fill
			(thermal_gap 0.5)
			(thermal_bridge_width 0.5)
			(island_removal_mode 0)
		)
		(polygon
			(pts
				(xy 192.066926 -247.776238) (xy 194.098926 -247.776238) (xy 194.098926 -248.004838) (xy 192.066926 -248.004838)
				(xy 191.900302 -248.004838) (xy 191.900302 -247.776238)
			)
		)
	)
	(zone
		(layer "F.Cu")
		(hatch none 0.5)
		(connect_pads
			(clearance 0)
		)
		(min_thickness 0.25)
		(keepout
			(tracks allowed)
			(vias allowed)
			(pads allowed)
			(copperpour allowed)
			(footprints allowed)
		)
		(placement
			(enabled no)
			(sheetname "")
		)
		(fill
			(thermal_gap 0.5)
			(thermal_bridge_width 0.5)
			(island_removal_mode 0)
		)
		(polygon
			(pts
				(xy 415.275776 -361.279948) (xy 413.459676 -361.279948) (xy 413.459676 -359.900728) (xy 415.275776 -359.900728)
			)
		)
	)
	(zone
		(layer "F.Cu")
		(hatch none 0.5)
		(connect_pads
			(clearance 0)
		)
		(min_thickness 0.25)
		(keepout
			(tracks allowed)
			(vias allowed)
			(pads allowed)
			(copperpour allowed)
			(footprints allowed)
		)
		(placement
			(enabled no)
			(sheetname "")
		)
		(fill
			(thermal_gap 0.5)
			(thermal_bridge_width 0.5)
			(island_removal_mode 0)
		)
		(polygon
			(pts
				(xy 63.80353 -277.512526) (xy 63.673228 -277.382224) (xy 63.673228 -277.080218) (xy 63.814198 -276.939248)
				(xy 66.290698 -276.939248) (xy 66.403474 -277.052024) (xy 66.403474 -277.44293) (xy 66.331338 -277.515066)
				(xy 66.25971 -277.515066) (xy 66.25971 -277.866602) (xy 66.212212 -277.866602) (xy 63.977012 -277.866602)
				(xy 63.80353 -277.866602)
			)
		)
	)
	(zone
		(layer "F.Cu")
		(hatch none 0.5)
		(connect_pads
			(clearance 0)
		)
		(min_thickness 0.25)
		(keepout
			(tracks allowed)
			(vias allowed)
			(pads allowed)
			(copperpour allowed)
			(footprints allowed)
		)
		(placement
			(enabled no)
			(sheetname "")
		)
		(fill
			(thermal_gap 0.5)
			(thermal_bridge_width 0.5)
			(island_removal_mode 0)
		)
		(polygon
			(pts
				(xy 440.006994 -200.407016) (xy 442.038994 -200.407016) (xy 442.038994 -200.178416) (xy 440.006994 -200.178416)
				(xy 439.875676 -200.178416) (xy 439.849768 -200.178416) (xy 439.849768 -200.407016) (xy 439.875676 -200.407016)
			)
		)
	)
	(zone
		(layer "F.Cu")
		(hatch none 0.5)
		(connect_pads
			(clearance 0)
		)
		(min_thickness 0.25)
		(keepout
			(tracks allowed)
			(vias allowed)
			(pads allowed)
			(copperpour allowed)
			(footprints allowed)
		)
		(placement
			(enabled no)
			(sheetname "")
		)
		(fill
			(thermal_gap 0.5)
			(thermal_bridge_width 0.5)
			(island_removal_mode 0)
		)
		(polygon
			(pts
				(xy 292.67531 -274.466558) (xy 292.67531 -274.02282) (xy 295.000426 -274.02282) (xy 295.000426 -274.466558)
			)
		)
	)
	(zone
		(layer "F.Cu")
		(hatch none 0.5)
		(connect_pads
			(clearance 0)
		)
		(min_thickness 0.25)
		(keepout
			(tracks allowed)
			(vias allowed)
			(pads allowed)
			(copperpour allowed)
			(footprints not_allowed)
		)
		(placement
			(enabled no)
			(sheetname "")
		)
		(fill
			(thermal_gap 0.5)
			(thermal_bridge_width 0.5)
			(island_removal_mode 0)
		)
		(polygon
			(pts
				(arc
					(start 291.980112 -419.999922)
					(mid 287.98012 -423.999914)
					(end 283.979874 -419.999922)
				)
				(arc
					(start 283.979874 -419.999922)
					(mid 287.98012 -415.999676)
					(end 291.980112 -419.999922)
				)
			)
		)
	)
	(zone
		(layer "F.Cu")
		(hatch none 0.5)
		(connect_pads
			(clearance 0)
		)
		(min_thickness 0.25)
		(keepout
			(tracks allowed)
			(vias allowed)
			(pads allowed)
			(copperpour allowed)
			(footprints not_allowed)
		)
		(placement
			(enabled no)
			(sheetname "")
		)
		(fill
			(thermal_gap 0.5)
			(thermal_bridge_width 0.5)
			(island_removal_mode 0)
		)
		(polygon
			(pts
				(arc
					(start 98.482912 -47.049944)
					(mid 100.383086 -45.14977)
					(end 102.283006 -47.049944)
				)
				(arc
					(start 102.283006 -47.049944)
					(mid 100.383086 -48.949864)
					(end 98.482912 -47.049944)
				)
			)
		)
	)
	(zone
		(layer "F.Cu")
		(hatch none 0.5)
		(connect_pads
			(clearance 0)
		)
		(min_thickness 0.25)
		(keepout
			(tracks allowed)
			(vias allowed)
			(pads allowed)
			(copperpour allowed)
			(footprints allowed)
		)
		(placement
			(enabled no)
			(sheetname "")
		)
		(fill
			(thermal_gap 0.5)
			(thermal_bridge_width 0.5)
			(island_removal_mode 0)
		)
		(polygon
			(pts
				(xy 137.48766 -287.393888) (xy 137.77468 -287.393888) (xy 137.80516 -287.363408) (xy 137.80516 -286.736028)
				(xy 137.7188 -286.649668) (xy 137.53084 -286.649668) (xy 137.45718 -286.723328) (xy 137.45718 -287.363408)
			)
		)
	)
	(zone
		(layer "F.Cu")
		(hatch none 0.5)
		(connect_pads
			(clearance 0)
		)
		(min_thickness 0.25)
		(keepout
			(tracks allowed)
			(vias allowed)
			(pads allowed)
			(copperpour allowed)
			(footprints allowed)
		)
		(placement
			(enabled no)
			(sheetname "")
		)
		(fill
			(thermal_gap 0.5)
			(thermal_bridge_width 0.5)
			(island_removal_mode 0)
		)
		(polygon
			(pts
				(xy 292.67531 -250.666504) (xy 292.67531 -250.222766) (xy 295.000426 -250.222766) (xy 295.000426 -250.666504)
			)
		)
	)
	(zone
		(layer "F.Cu")
		(hatch none 0.5)
		(connect_pads
			(clearance 0)
		)
		(min_thickness 0.25)
		(keepout
			(tracks allowed)
			(vias allowed)
			(pads allowed)
			(copperpour allowed)
			(footprints allowed)
		)
		(placement
			(enabled no)
			(sheetname "")
		)
		(fill
			(thermal_gap 0.5)
			(thermal_bridge_width 0.5)
			(island_removal_mode 0)
		)
		(polygon
			(pts
				(xy 262.50011 -262.566658) (xy 262.50011 -262.12292) (xy 264.825226 -262.12292) (xy 264.825226 -262.566658)
			)
		)
	)
	(zone
		(layer "F.Cu")
		(hatch none 0.5)
		(connect_pads
			(clearance 0)
		)
		(min_thickness 0.25)
		(keepout
			(tracks allowed)
			(vias allowed)
			(pads allowed)
			(copperpour allowed)
			(footprints allowed)
		)
		(placement
			(enabled no)
			(sheetname "")
		)
		(fill
			(thermal_gap 0.5)
			(thermal_bridge_width 0.5)
			(island_removal_mode 0)
		)
		(polygon
			(pts
				(xy 307.76291 -311.01665) (xy 307.76291 -310.572912) (xy 310.088026 -310.572912) (xy 310.088026 -311.01665)
			)
		)
	)
	(zone
		(layer "F.Cu")
		(hatch none 0.5)
		(connect_pads
			(clearance 0)
		)
		(min_thickness 0.25)
		(keepout
			(tracks allowed)
			(vias allowed)
			(pads allowed)
			(copperpour allowed)
			(footprints allowed)
		)
		(placement
			(enabled no)
			(sheetname "")
		)
		(fill
			(thermal_gap 0.5)
			(thermal_bridge_width 0.5)
			(island_removal_mode 0)
		)
		(polygon
			(pts
				(xy 138.26236 -219.316808) (xy 138.54938 -219.316808) (xy 138.57986 -219.286328) (xy 138.57986 -218.658948)
				(xy 138.4935 -218.572588) (xy 138.30554 -218.572588) (xy 138.23188 -218.646248) (xy 138.23188 -219.286328)
			)
		)
	)
	(zone
		(layer "F.Cu")
		(hatch none 0.5)
		(connect_pads
			(clearance 0)
		)
		(min_thickness 0.25)
		(keepout
			(tracks allowed)
			(vias allowed)
			(pads allowed)
			(copperpour allowed)
			(footprints allowed)
		)
		(placement
			(enabled no)
			(sheetname "")
		)
		(fill
			(thermal_gap 0.5)
			(thermal_bridge_width 0.5)
			(island_removal_mode 0)
		)
		(polygon
			(pts
				(xy 192.066926 -258.826254) (xy 194.098926 -258.826254) (xy 194.098926 -259.054854) (xy 192.066926 -259.054854)
				(xy 191.891158 -259.054854) (xy 191.891158 -258.826254)
			)
		)
	)
	(zone
		(layer "F.Cu")
		(hatch none 0.5)
		(connect_pads
			(clearance 0)
		)
		(min_thickness 0.25)
		(keepout
			(tracks allowed)
			(vias allowed)
			(pads allowed)
			(copperpour allowed)
			(footprints not_allowed)
		)
		(placement
			(enabled no)
			(sheetname "")
		)
		(fill
			(thermal_gap 0.5)
			(thermal_bridge_width 0.5)
			(island_removal_mode 0)
		)
		(polygon
			(pts
				(xy 107.430062 -52.55006) (xy 107.430062 -41.550082) (xy 80.674464 -41.550082) (xy 80.669892 -52.55006)
			)
		)
	)
	(zone
		(layer "F.Cu")
		(hatch none 0.5)
		(connect_pads
			(clearance 0)
		)
		(min_thickness 0.25)
		(keepout
			(tracks allowed)
			(vias allowed)
			(pads allowed)
			(copperpour allowed)
			(footprints allowed)
		)
		(placement
			(enabled no)
			(sheetname "")
		)
		(fill
			(thermal_gap 0.5)
			(thermal_bridge_width 0.5)
			(island_removal_mode 0)
		)
		(polygon
			(pts
				(xy 26.20391 -265.966448) (xy 26.20391 -265.52271) (xy 28.529026 -265.52271) (xy 28.529026 -265.966448)
			)
		)
	)
	(zone
		(layer "F.Cu")
		(hatch none 0.5)
		(connect_pads
			(clearance 0)
		)
		(min_thickness 0.25)
		(keepout
			(tracks allowed)
			(vias allowed)
			(pads allowed)
			(copperpour allowed)
			(footprints allowed)
		)
		(placement
			(enabled no)
			(sheetname "")
		)
		(fill
			(thermal_gap 0.5)
			(thermal_bridge_width 0.5)
			(island_removal_mode 0)
		)
		(polygon
			(pts
				(xy 29.647642 -305.066446) (xy 29.647642 -304.622708) (xy 31.972758 -304.622708) (xy 31.972758 -305.066446)
			)
		)
	)
	(zone
		(layer "F.Cu")
		(hatch none 0.5)
		(connect_pads
			(clearance 0)
		)
		(min_thickness 0.25)
		(keepout
			(tracks allowed)
			(vias allowed)
			(pads allowed)
			(copperpour allowed)
			(footprints allowed)
		)
		(placement
			(enabled no)
			(sheetname "")
		)
		(fill
			(thermal_gap 0.5)
			(thermal_bridge_width 0.5)
			(island_removal_mode 0)
		)
		(polygon
			(pts
				(xy 274.143978 -294.01643) (xy 274.143978 -293.572692) (xy 276.469094 -293.572692) (xy 276.469094 -294.01643)
			)
		)
	)
	(zone
		(layer "F.Cu")
		(hatch none 0.5)
		(connect_pads
			(clearance 0)
		)
		(min_thickness 0.25)
		(keepout
			(tracks allowed)
			(vias allowed)
			(pads allowed)
			(copperpour allowed)
			(footprints not_allowed)
		)
		(placement
			(enabled no)
			(sheetname "")
		)
		(fill
			(thermal_gap 0.5)
			(thermal_bridge_width 0.5)
			(island_removal_mode 0)
		)
		(polygon
			(pts
				(xy 71.929752 -311.770014) (xy 151.929846 -311.770014) (xy 151.929846 -191.77) (xy 71.929752 -191.77)
			)
		)
	)
	(zone
		(layer "F.Cu")
		(hatch none 0.5)
		(connect_pads
			(clearance 0)
		)
		(min_thickness 0.25)
		(keepout
			(tracks allowed)
			(vias allowed)
			(pads allowed)
			(copperpour allowed)
			(footprints allowed)
		)
		(placement
			(enabled no)
			(sheetname "")
		)
		(fill
			(thermal_gap 0.5)
			(thermal_bridge_width 0.5)
			(island_removal_mode 0)
		)
		(polygon
			(pts
				(xy 161.891726 -229.926388) (xy 163.923726 -229.926388) (xy 163.923726 -230.154988) (xy 161.891726 -230.154988)
				(xy 161.755582 -230.154988) (xy 161.708592 -230.154988) (xy 161.708592 -229.926388) (xy 161.755582 -229.926388)
			)
		)
	)
	(zone
		(layer "F.Cu")
		(hatch none 0.5)
		(connect_pads
			(clearance 0)
		)
		(min_thickness 0.25)
		(keepout
			(tracks allowed)
			(vias allowed)
			(pads allowed)
			(copperpour allowed)
			(footprints not_allowed)
		)
		(placement
			(enabled no)
			(sheetname "")
		)
		(fill
			(thermal_gap 0.5)
			(thermal_bridge_width 0.5)
			(island_removal_mode 0)
		)
		(polygon
			(pts
				(arc
					(start 64.382904 -50.25009)
					(mid 67.582796 -47.050198)
					(end 64.382904 -43.850052)
				)
				(arc
					(start 62.782958 -43.850052)
					(mid 59.582812 -47.050198)
					(end 62.782958 -50.25009)
				)
			)
		)
	)
	(zone
		(layer "F.Cu")
		(hatch none 0.5)
		(connect_pads
			(clearance 0)
		)
		(min_thickness 0.25)
		(keepout
			(tracks allowed)
			(vias allowed)
			(pads allowed)
			(copperpour allowed)
			(footprints allowed)
		)
		(placement
			(enabled no)
			(sheetname "")
		)
		(fill
			(thermal_gap 0.5)
			(thermal_bridge_width 0.5)
			(island_removal_mode 0)
		)
		(polygon
			(pts
				(xy 192.066926 -274.976336) (xy 194.098926 -274.976336) (xy 194.098926 -274.978622) (xy 194.277742 -274.978622)
				(xy 194.277742 -275.215858) (xy 194.458844 -275.39696) (xy 194.474338 -275.412454) (xy 194.474338 -275.60143)
				(xy 194.458844 -275.616924) (xy 194.347846 -275.727922) (xy 194.307206 -275.768562) (xy 191.845946 -275.768562)
				(xy 191.704722 -275.627338) (xy 191.704722 -275.430234) (xy 191.786256 -275.3487) (xy 191.845184 -275.289772)
				(xy 191.845184 -274.976336) (xy 191.883792 -274.976336) (xy 191.930782 -274.976336)
			)
		)
	)
	(zone
		(layer "F.Cu")
		(hatch none 0.5)
		(connect_pads
			(clearance 0)
		)
		(min_thickness 0.25)
		(keepout
			(tracks not_allowed)
			(vias allowed)
			(pads allowed)
			(copperpour not_allowed)
			(footprints allowed)
		)
		(placement
			(enabled no)
			(sheetname "")
		)
		(fill
			(thermal_gap 0.5)
			(thermal_bridge_width 0.5)
			(island_removal_mode 0)
		)
		(polygon
			(pts
				(arc
					(start 148.034756 -251.76988)
					(mid 145.939764 -253.864872)
					(end 143.844772 -251.76988)
				)
				(arc
					(start 143.844772 -251.76988)
					(mid 145.939764 -249.674888)
					(end 148.034756 -251.76988)
				)
			)
		)
	)
	(zone
		(layer "F.Cu")
		(hatch none 0.5)
		(connect_pads
			(clearance 0)
		)
		(min_thickness 0.25)
		(keepout
			(tracks allowed)
			(vias allowed)
			(pads allowed)
			(copperpour allowed)
			(footprints allowed)
		)
		(placement
			(enabled no)
			(sheetname "")
		)
		(fill
			(thermal_gap 0.5)
			(thermal_bridge_width 0.5)
			(island_removal_mode 0)
		)
		(polygon
			(pts
				(xy 56.37911 -202.216512) (xy 56.37911 -201.772774) (xy 58.704226 -201.772774) (xy 58.704226 -202.216512)
			)
		)
	)
	(zone
		(layer "F.Cu")
		(hatch none 0.5)
		(connect_pads
			(clearance 0)
		)
		(min_thickness 0.25)
		(keepout
			(tracks not_allowed)
			(vias allowed)
			(pads allowed)
			(copperpour not_allowed)
			(footprints allowed)
		)
		(placement
			(enabled no)
			(sheetname "")
		)
		(fill
			(thermal_gap 0.5)
			(thermal_bridge_width 0.5)
			(island_removal_mode 0)
		)
		(polygon
			(pts
				(xy 439.968894 -9.0424) (xy 440.144154 -9.0424) (xy 440.172094 -9.01446) (xy 440.172094 -7.62) (xy 440.149234 -7.59714)
				(xy 439.979054 -7.59714) (xy 439.958734 -7.61746) (xy 439.958734 -9.03224)
			)
		)
	)
	(zone
		(layer "F.Cu")
		(hatch none 0.5)
		(connect_pads
			(clearance 0)
		)
		(min_thickness 0.25)
		(keepout
			(tracks allowed)
			(vias allowed)
			(pads allowed)
			(copperpour allowed)
			(footprints not_allowed)
		)
		(placement
			(enabled no)
			(sheetname "")
		)
		(fill
			(thermal_gap 0.5)
			(thermal_bridge_width 0.5)
			(island_removal_mode 0)
		)
		(polygon
			(pts
				(arc
					(start 307.999892 -76.950062)
					(mid 308.732161 -78.717915)
					(end 310.500014 -79.44993)
				)
				(xy 365.799878 -79.44993)
				(arc
					(start 365.799878 -19.949922)
					(mid 365.067684 -18.182248)
					(end 363.30001 -17.450054)
				)
				(xy 307.999892 -17.450054)
			)
		)
	)
	(zone
		(layer "F.Cu")
		(hatch none 0.5)
		(connect_pads
			(clearance 0)
		)
		(min_thickness 0.25)
		(keepout
			(tracks allowed)
			(vias allowed)
			(pads allowed)
			(copperpour allowed)
			(footprints allowed)
		)
		(placement
			(enabled no)
			(sheetname "")
		)
		(fill
			(thermal_gap 0.5)
			(thermal_bridge_width 0.5)
			(island_removal_mode 0)
		)
		(polygon
			(pts
				(xy 44.735242 -314.41644) (xy 44.735242 -313.972702) (xy 47.060358 -313.972702) (xy 47.060358 -314.41644)
			)
		)
	)
	(zone
		(layer "F.Cu")
		(hatch none 0.5)
		(connect_pads
			(clearance 0)
		)
		(min_thickness 0.25)
		(keepout
			(tracks allowed)
			(vias allowed)
			(pads allowed)
			(copperpour allowed)
			(footprints allowed)
		)
		(placement
			(enabled no)
			(sheetname "")
		)
		(fill
			(thermal_gap 0.5)
			(thermal_bridge_width 0.5)
			(island_removal_mode 0)
		)
		(polygon
			(pts
				(xy 307.76291 -309.316628) (xy 307.76291 -308.87289) (xy 310.088026 -308.87289) (xy 310.088026 -309.316628)
			)
		)
	)
	(zone
		(layer "F.Cu")
		(hatch none 0.5)
		(connect_pads
			(clearance 0)
		)
		(min_thickness 0.25)
		(keepout
			(tracks allowed)
			(vias allowed)
			(pads allowed)
			(copperpour allowed)
			(footprints allowed)
		)
		(placement
			(enabled no)
			(sheetname "")
		)
		(fill
			(thermal_gap 0.5)
			(thermal_bridge_width 0.5)
			(island_removal_mode 0)
		)
		(polygon
			(pts
				(xy 56.37911 -297.416474) (xy 56.37911 -296.972736) (xy 58.704226 -296.972736) (xy 58.704226 -297.416474)
			)
		)
	)
	(zone
		(layer "F.Cu")
		(hatch none 0.5)
		(connect_pads
			(clearance 0)
		)
		(min_thickness 0.25)
		(keepout
			(tracks allowed)
			(vias allowed)
			(pads allowed)
			(copperpour allowed)
			(footprints allowed)
		)
		(placement
			(enabled no)
			(sheetname "")
		)
		(fill
			(thermal_gap 0.5)
			(thermal_bridge_width 0.5)
			(island_removal_mode 0)
		)
		(polygon
			(pts
				(xy 44.735242 -230.266494) (xy 44.735242 -229.822756) (xy 47.060358 -229.822756) (xy 47.060358 -230.266494)
			)
		)
	)
	(zone
		(layer "F.Cu")
		(hatch none 0.5)
		(connect_pads
			(clearance 0)
		)
		(min_thickness 0.25)
		(keepout
			(tracks allowed)
			(vias allowed)
			(pads allowed)
			(copperpour allowed)
			(footprints allowed)
		)
		(placement
			(enabled no)
			(sheetname "")
		)
		(fill
			(thermal_gap 0.5)
			(thermal_bridge_width 0.5)
			(island_removal_mode 0)
		)
		(polygon
			(pts
				(xy 262.50011 -305.066446) (xy 262.50011 -304.622708) (xy 264.825226 -304.622708) (xy 264.825226 -305.066446)
			)
		)
	)
	(zone
		(layer "F.Cu")
		(hatch none 0.5)
		(connect_pads
			(clearance 0)
		)
		(min_thickness 0.25)
		(keepout
			(tracks allowed)
			(vias allowed)
			(pads allowed)
			(copperpour allowed)
			(footprints allowed)
		)
		(placement
			(enabled no)
			(sheetname "")
		)
		(fill
			(thermal_gap 0.5)
			(thermal_bridge_width 0.5)
			(island_removal_mode 0)
		)
		(polygon
			(pts
				(xy 41.29151 -300.816518) (xy 41.29151 -300.37278) (xy 43.616626 -300.37278) (xy 43.616626 -300.816518)
			)
		)
	)
	(zone
		(layer "F.Cu")
		(hatch none 0.5)
		(connect_pads
			(clearance 0)
		)
		(min_thickness 0.25)
		(keepout
			(tracks allowed)
			(vias allowed)
			(pads allowed)
			(copperpour allowed)
			(footprints allowed)
		)
		(placement
			(enabled no)
			(sheetname "")
		)
		(fill
			(thermal_gap 0.5)
			(thermal_bridge_width 0.5)
			(island_removal_mode 0)
		)
		(polygon
			(pts
				(xy 440.006994 -206.976472) (xy 442.038994 -206.976472) (xy 442.038994 -207.205072) (xy 440.006994 -207.205072)
				(xy 439.87085 -207.205072) (xy 439.82386 -207.205072) (xy 439.82386 -206.976472) (xy 439.87085 -206.976472)
			)
		)
	)
	(zone
		(layer "F.Cu")
		(hatch none 0.5)
		(connect_pads
			(clearance 0)
		)
		(min_thickness 0.25)
		(keepout
			(tracks allowed)
			(vias allowed)
			(pads allowed)
			(copperpour allowed)
			(footprints allowed)
		)
		(placement
			(enabled no)
			(sheetname "")
		)
		(fill
			(thermal_gap 0.5)
			(thermal_bridge_width 0.5)
			(island_removal_mode 0)
		)
		(polygon
			(pts
				(xy 307.76291 -263.416542) (xy 307.76291 -262.972804) (xy 310.088026 -262.972804) (xy 310.088026 -263.416542)
			)
		)
	)
	(zone
		(layer "F.Cu")
		(hatch none 0.5)
		(connect_pads
			(clearance 0)
		)
		(min_thickness 0.25)
		(keepout
			(tracks allowed)
			(vias allowed)
			(pads allowed)
			(copperpour allowed)
			(footprints allowed)
		)
		(placement
			(enabled no)
			(sheetname "")
		)
		(fill
			(thermal_gap 0.5)
			(thermal_bridge_width 0.5)
			(island_removal_mode 0)
		)
		(polygon
			(pts
				(xy 56.37911 -295.716452) (xy 56.37911 -295.272714) (xy 58.704226 -295.272714) (xy 58.704226 -295.716452)
			)
		)
	)
	(zone
		(layer "F.Cu")
		(hatch none 0.5)
		(connect_pads
			(clearance 0)
		)
		(min_thickness 0.25)
		(keepout
			(tracks allowed)
			(vias allowed)
			(pads allowed)
			(copperpour allowed)
			(footprints allowed)
		)
		(placement
			(enabled no)
			(sheetname "")
		)
		(fill
			(thermal_gap 0.5)
			(thermal_bridge_width 0.5)
			(island_removal_mode 0)
		)
		(polygon
			(pts
				(xy 409.831794 -229.07625) (xy 411.863794 -229.07625) (xy 411.863794 -229.30485) (xy 409.831794 -229.30485)
				(xy 409.661868 -229.30485) (xy 409.642056 -229.30485) (xy 409.642056 -229.07625) (xy 409.661868 -229.07625)
			)
		)
	)
	(zone
		(layer "F.Cu")
		(hatch none 0.5)
		(connect_pads
			(clearance 0)
		)
		(min_thickness 0.25)
		(keepout
			(tracks allowed)
			(vias allowed)
			(pads allowed)
			(copperpour allowed)
			(footprints allowed)
		)
		(placement
			(enabled no)
			(sheetname "")
		)
		(fill
			(thermal_gap 0.5)
			(thermal_bridge_width 0.5)
			(island_removal_mode 0)
		)
		(polygon
			(pts
				(xy 354.18268 -361.163108) (xy 354.18268 -356.570788) (xy 358.775 -356.570788) (xy 358.775 -361.163108)
			)
		)
	)
	(zone
		(layer "F.Cu")
		(hatch none 0.5)
		(connect_pads
			(clearance 0)
		)
		(min_thickness 0.25)
		(keepout
			(tracks allowed)
			(vias allowed)
			(pads allowed)
			(copperpour allowed)
			(footprints allowed)
		)
		(placement
			(enabled no)
			(sheetname "")
		)
		(fill
			(thermal_gap 0.5)
			(thermal_bridge_width 0.5)
			(island_removal_mode 0)
		)
		(polygon
			(pts
				(xy 413.275526 -202.105006) (xy 413.275526 -201.876406) (xy 415.307526 -201.876406) (xy 415.307526 -202.105006)
			)
		)
	)
	(zone
		(layer "F.Cu")
		(hatch none 0.5)
		(connect_pads
			(clearance 0)
		)
		(min_thickness 0.25)
		(keepout
			(tracks allowed)
			(vias allowed)
			(pads allowed)
			(copperpour allowed)
			(footprints allowed)
		)
		(placement
			(enabled no)
			(sheetname "")
		)
		(fill
			(thermal_gap 0.5)
			(thermal_bridge_width 0.5)
			(island_removal_mode 0)
		)
		(polygon
			(pts
				(xy 27.38374 -5.870448) (xy 27.38374 -3.983228) (xy 29.49702 -3.983228) (xy 29.49702 -5.870448)
			)
		)
	)
	(zone
		(layer "F.Cu")
		(hatch none 0.5)
		(connect_pads
			(clearance 0)
		)
		(min_thickness 0.25)
		(keepout
			(tracks allowed)
			(vias allowed)
			(pads allowed)
			(copperpour allowed)
			(footprints allowed)
		)
		(placement
			(enabled no)
			(sheetname "")
		)
		(fill
			(thermal_gap 0.5)
			(thermal_bridge_width 0.5)
			(island_removal_mode 0)
		)
		(polygon
			(pts
				(xy 11.11631 -264.266426) (xy 11.11631 -263.822688) (xy 13.441426 -263.822688) (xy 13.441426 -264.266426)
			)
		)
	)
	(zone
		(layer "F.Cu")
		(hatch none 0.5)
		(connect_pads
			(clearance 0)
		)
		(min_thickness 0.25)
		(keepout
			(tracks allowed)
			(vias allowed)
			(pads allowed)
			(copperpour allowed)
			(footprints allowed)
		)
		(placement
			(enabled no)
			(sheetname "")
		)
		(fill
			(thermal_gap 0.5)
			(thermal_bridge_width 0.5)
			(island_removal_mode 0)
		)
		(polygon
			(pts
				(xy 274.143978 -245.566438) (xy 274.143978 -245.1227) (xy 276.469094 -245.1227) (xy 276.469094 -245.566438)
			)
		)
	)
	(zone
		(layer "F.Cu")
		(hatch none 0.5)
		(connect_pads
			(clearance 0)
		)
		(min_thickness 0.25)
		(keepout
			(tracks allowed)
			(vias allowed)
			(pads allowed)
			(copperpour allowed)
			(footprints allowed)
		)
		(placement
			(enabled no)
			(sheetname "")
		)
		(fill
			(thermal_gap 0.5)
			(thermal_bridge_width 0.5)
			(island_removal_mode 0)
		)
		(polygon
			(pts
				(xy 424.919394 -247.776238) (xy 426.951394 -247.776238) (xy 426.951394 -248.004838) (xy 424.919394 -248.004838)
				(xy 424.75277 -248.004838) (xy 424.75277 -247.776238)
			)
		)
	)
	(zone
		(layer "F.Cu")
		(hatch none 0.5)
		(connect_pads
			(clearance 0)
		)
		(min_thickness 0.25)
		(keepout
			(tracks allowed)
			(vias allowed)
			(pads allowed)
			(copperpour allowed)
			(footprints allowed)
		)
		(placement
			(enabled no)
			(sheetname "")
		)
		(fill
			(thermal_gap 0.5)
			(thermal_bridge_width 0.5)
			(island_removal_mode 0)
		)
		(polygon
			(pts
				(xy 63.977012 -278.272748) (xy 66.161412 -278.272748) (xy 66.310764 -278.272748) (xy 66.310764 -278.65578)
				(xy 66.460878 -278.805894) (xy 66.460878 -279.095962) (xy 66.348102 -279.208738) (xy 63.835534 -279.208738)
				(xy 63.694564 -279.067768) (xy 63.694564 -278.733504) (xy 63.803276 -278.624792) (xy 63.803276 -278.272748)
				(xy 63.85433 -278.272748)
			)
		)
	)
	(zone
		(layer "F.Cu")
		(hatch none 0.5)
		(connect_pads
			(clearance 0)
		)
		(min_thickness 0.25)
		(keepout
			(tracks allowed)
			(vias allowed)
			(pads allowed)
			(copperpour allowed)
			(footprints allowed)
		)
		(placement
			(enabled no)
			(sheetname "")
		)
		(fill
			(thermal_gap 0.5)
			(thermal_bridge_width 0.5)
			(island_removal_mode 0)
		)
		(polygon
			(pts
				(xy 87.258398 -277.466806) (xy 87.461344 -277.26386) (xy 87.461344 -277.22068) (xy 87.017606 -276.776942)
				(xy 86.895432 -276.776942) (xy 86.76259 -276.910038) (xy 86.76259 -277.014178) (xy 87.215218 -277.466806)
			)
		)
	)
	(zone
		(layer "F.Cu")
		(hatch none 0.5)
		(connect_pads
			(clearance 0)
		)
		(min_thickness 0.25)
		(keepout
			(tracks allowed)
			(vias allowed)
			(pads allowed)
			(copperpour allowed)
			(footprints not_allowed)
		)
		(placement
			(enabled no)
			(sheetname "")
		)
		(fill
			(thermal_gap 0.5)
			(thermal_bridge_width 0.5)
			(island_removal_mode 0)
		)
		(polygon
			(pts
				(arc
					(start 198.399908 -22.29993)
					(mid 203.399898 -17.29994)
					(end 208.399888 -22.29993)
				)
				(arc
					(start 208.399888 -22.29993)
					(mid 203.399898 -27.29992)
					(end 198.399908 -22.29993)
				)
			)
		)
	)
	(zone
		(layer "F.Cu")
		(hatch none 0.5)
		(connect_pads
			(clearance 0)
		)
		(min_thickness 0.25)
		(keepout
			(tracks allowed)
			(vias allowed)
			(pads allowed)
			(copperpour allowed)
			(footprints allowed)
		)
		(placement
			(enabled no)
			(sheetname "")
		)
		(fill
			(thermal_gap 0.5)
			(thermal_bridge_width 0.5)
			(island_removal_mode 0)
		)
		(polygon
			(pts
				(xy 304.319178 -285.516574) (xy 304.319178 -285.072836) (xy 306.644294 -285.072836) (xy 306.644294 -285.516574)
			)
		)
	)
	(zone
		(layer "F.Cu")
		(hatch none 0.5)
		(connect_pads
			(clearance 0)
		)
		(min_thickness 0.25)
		(keepout
			(tracks allowed)
			(vias allowed)
			(pads allowed)
			(copperpour allowed)
			(footprints allowed)
		)
		(placement
			(enabled no)
			(sheetname "")
		)
		(fill
			(thermal_gap 0.5)
			(thermal_bridge_width 0.5)
			(island_removal_mode 0)
		)
		(polygon
			(pts
				(xy 405.731726 -291.355018) (xy 405.731726 -291.126418) (xy 407.763726 -291.126418) (xy 407.763726 -291.355018)
			)
		)
	)
	(zone
		(layer "F.Cu")
		(hatch none 0.5)
		(connect_pads
			(clearance 0)
		)
		(min_thickness 0.25)
		(keepout
			(tracks allowed)
			(vias allowed)
			(pads allowed)
			(copperpour allowed)
			(footprints not_allowed)
		)
		(placement
			(enabled no)
			(sheetname "")
		)
		(fill
			(thermal_gap 0.5)
			(thermal_bridge_width 0.5)
			(island_removal_mode 0)
		)
		(polygon
			(pts
				(xy 275.815044 -424.126914) (xy 196.004942 -424.126914) (xy 196.004942 -439.669936) (xy 199.205088 -439.669936)
				(xy 199.205088 -427.32706) (xy 272.614898 -427.32706) (xy 272.614898 -439.669936) (xy 275.815044 -439.669936)
			)
		)
	)
	(zone
		(layer "F.Cu")
		(hatch none 0.5)
		(connect_pads
			(clearance 0)
		)
		(min_thickness 0.25)
		(keepout
			(tracks allowed)
			(vias allowed)
			(pads allowed)
			(copperpour allowed)
			(footprints allowed)
		)
		(placement
			(enabled no)
			(sheetname "")
		)
		(fill
			(thermal_gap 0.5)
			(thermal_bridge_width 0.5)
			(island_removal_mode 0)
		)
		(polygon
			(pts
				(xy 262.50011 -289.766502) (xy 262.50011 -289.322764) (xy 264.825226 -289.322764) (xy 264.825226 -289.766502)
			)
		)
	)
	(zone
		(layer "F.Cu")
		(hatch none 0.5)
		(connect_pads
			(clearance 0)
		)
		(min_thickness 0.25)
		(keepout
			(tracks allowed)
			(vias allowed)
			(pads allowed)
			(copperpour allowed)
			(footprints allowed)
		)
		(placement
			(enabled no)
			(sheetname "")
		)
		(fill
			(thermal_gap 0.5)
			(thermal_bridge_width 0.5)
			(island_removal_mode 0)
		)
		(polygon
			(pts
				(xy 425.840398 -364.330488) (xy 424.092878 -364.330488) (xy 424.092878 -362.395008) (xy 425.840398 -362.395008)
			)
		)
	)
	(zone
		(layer "F.Cu")
		(hatch none 0.5)
		(connect_pads
			(clearance 0)
		)
		(min_thickness 0.25)
		(keepout
			(tracks not_allowed)
			(vias allowed)
			(pads allowed)
			(copperpour not_allowed)
			(footprints allowed)
		)
		(placement
			(enabled no)
			(sheetname "")
		)
		(fill
			(thermal_gap 0.5)
			(thermal_bridge_width 0.5)
			(island_removal_mode 0)
		)
		(polygon
			(pts
				(arc
					(start 199.64527 -51.999896)
					(mid 204.64526 -46.999906)
					(end 209.64525 -51.999896)
				)
				(arc
					(start 209.64525 -51.999896)
					(mid 204.64526 -56.999886)
					(end 199.64527 -51.999896)
				)
			)
		)
	)
	(zone
		(layer "F.Cu")
		(hatch none 0.5)
		(connect_pads
			(clearance 0)
		)
		(min_thickness 0.25)
		(keepout
			(tracks not_allowed)
			(vias allowed)
			(pads allowed)
			(copperpour not_allowed)
			(footprints allowed)
		)
		(placement
			(enabled no)
			(sheetname "")
		)
		(fill
			(thermal_gap 0.5)
			(thermal_bridge_width 0.5)
			(island_removal_mode 0)
		)
		(polygon
			(pts
				(xy 230.650034 -46.999906) (xy 230.650034 -41.999916) (xy 226.44989 -41.999916) (xy 226.44989 -46.999906)
			)
		)
	)
	(zone
		(layer "F.Cu")
		(hatch none 0.5)
		(connect_pads
			(clearance 0)
		)
		(min_thickness 0.25)
		(keepout
			(tracks allowed)
			(vias allowed)
			(pads allowed)
			(copperpour allowed)
			(footprints allowed)
		)
		(placement
			(enabled no)
			(sheetname "")
		)
		(fill
			(thermal_gap 0.5)
			(thermal_bridge_width 0.5)
			(island_removal_mode 0)
		)
		(polygon
			(pts
				(xy 56.37911 -248.116598) (xy 56.37911 -247.67286) (xy 58.704226 -247.67286) (xy 58.704226 -248.116598)
			)
		)
	)
	(zone
		(layer "F.Cu")
		(hatch none 0.5)
		(connect_pads
			(clearance 0)
		)
		(min_thickness 0.25)
		(keepout
			(tracks allowed)
			(vias allowed)
			(pads allowed)
			(copperpour allowed)
			(footprints allowed)
		)
		(placement
			(enabled no)
			(sheetname "")
		)
		(fill
			(thermal_gap 0.5)
			(thermal_bridge_width 0.5)
			(island_removal_mode 0)
		)
		(polygon
			(pts
				(xy 26.20391 -272.322798) (xy 28.529026 -272.322798) (xy 28.598876 -272.322798) (xy 28.598876 -273.258534)
				(xy 26.086308 -273.258534) (xy 26.086308 -272.322798)
			)
		)
	)
	(zone
		(layer "F.Cu")
		(hatch none 0.5)
		(connect_pads
			(clearance 0)
		)
		(min_thickness 0.25)
		(keepout
			(tracks allowed)
			(vias allowed)
			(pads allowed)
			(copperpour allowed)
			(footprints allowed)
		)
		(placement
			(enabled no)
			(sheetname "")
		)
		(fill
			(thermal_gap 0.5)
			(thermal_bridge_width 0.5)
			(island_removal_mode 0)
		)
		(polygon
			(pts
				(xy 31.972758 -277.016464) (xy 29.647642 -277.016464) (xy 29.520896 -277.016464) (xy 29.520896 -276.07514)
				(xy 32.045656 -276.07514) (xy 32.045656 -277.016464)
			)
		)
	)
	(zone
		(layer "F.Cu")
		(hatch none 0.5)
		(connect_pads
			(clearance 0)
		)
		(min_thickness 0.25)
		(keepout
			(tracks allowed)
			(vias allowed)
			(pads allowed)
			(copperpour allowed)
			(footprints allowed)
		)
		(placement
			(enabled no)
			(sheetname "")
		)
		(fill
			(thermal_gap 0.5)
			(thermal_bridge_width 0.5)
			(island_removal_mode 0)
		)
		(polygon
			(pts
				(xy 443.450726 -196.154802) (xy 443.450726 -195.926202) (xy 445.482726 -195.926202) (xy 445.482726 -196.154802)
			)
		)
	)
	(zone
		(layer "F.Cu")
		(hatch none 0.5)
		(connect_pads
			(clearance 0)
		)
		(min_thickness 0.25)
		(keepout
			(tracks allowed)
			(vias allowed)
			(pads allowed)
			(copperpour allowed)
			(footprints allowed)
		)
		(placement
			(enabled no)
			(sheetname "")
		)
		(fill
			(thermal_gap 0.5)
			(thermal_bridge_width 0.5)
			(island_removal_mode 0)
		)
		(polygon
			(pts
				(xy 443.450726 -208.90484) (xy 443.450726 -208.67624) (xy 445.482726 -208.67624) (xy 445.482726 -208.90484)
			)
		)
	)
	(zone
		(layer "F.Cu")
		(hatch none 0.5)
		(connect_pads
			(clearance 0)
		)
		(min_thickness 0.25)
		(keepout
			(tracks allowed)
			(vias allowed)
			(pads allowed)
			(copperpour allowed)
			(footprints allowed)
		)
		(placement
			(enabled no)
			(sheetname "")
		)
		(fill
			(thermal_gap 0.5)
			(thermal_bridge_width 0.5)
			(island_removal_mode 0)
		)
		(polygon
			(pts
				(xy 405.731726 -316.004956) (xy 405.731726 -315.776356) (xy 407.763726 -315.776356) (xy 407.763726 -316.004956)
			)
		)
	)
	(zone
		(layer "F.Cu")
		(hatch none 0.5)
		(connect_pads
			(clearance 0)
		)
		(min_thickness 0.25)
		(keepout
			(tracks allowed)
			(vias allowed)
			(pads allowed)
			(copperpour allowed)
			(footprints allowed)
		)
		(placement
			(enabled no)
			(sheetname "")
		)
		(fill
			(thermal_gap 0.5)
			(thermal_bridge_width 0.5)
			(island_removal_mode 0)
		)
		(polygon
			(pts
				(xy 14.560042 -283.816552) (xy 14.560042 -283.372814) (xy 16.885158 -283.372814) (xy 16.885158 -283.816552)
			)
		)
	)
	(zone
		(layer "F.Cu")
		(hatch none 0.5)
		(connect_pads
			(clearance 0)
		)
		(min_thickness 0.25)
		(keepout
			(tracks allowed)
			(vias allowed)
			(pads allowed)
			(copperpour allowed)
			(footprints allowed)
		)
		(placement
			(enabled no)
			(sheetname "")
		)
		(fill
			(thermal_gap 0.5)
			(thermal_bridge_width 0.5)
			(island_removal_mode 0)
		)
		(polygon
			(pts
				(xy 176.979326 -261.376414) (xy 179.011326 -261.376414) (xy 179.011326 -261.605014) (xy 176.979326 -261.605014)
				(xy 176.812702 -261.605014) (xy 176.812702 -261.376414)
			)
		)
	)
	(zone
		(layer "F.Cu")
		(hatch none 0.5)
		(connect_pads
			(clearance 0)
		)
		(min_thickness 0.25)
		(keepout
			(tracks allowed)
			(vias allowed)
			(pads allowed)
			(copperpour allowed)
			(footprints allowed)
		)
		(placement
			(enabled no)
			(sheetname "")
		)
		(fill
			(thermal_gap 0.5)
			(thermal_bridge_width 0.5)
			(island_removal_mode 0)
		)
		(polygon
			(pts
				(xy 207.154526 -270.726408) (xy 209.186526 -270.726408) (xy 209.186526 -270.955008) (xy 207.154526 -270.955008)
				(xy 207.018382 -270.955008) (xy 206.971392 -270.955008) (xy 206.971392 -270.726408) (xy 207.018382 -270.726408)
			)
		)
	)
	(zone
		(layer "F.Cu")
		(hatch none 0.5)
		(connect_pads
			(clearance 0)
		)
		(min_thickness 0.25)
		(keepout
			(tracks not_allowed)
			(vias allowed)
			(pads allowed)
			(copperpour not_allowed)
			(footprints allowed)
		)
		(placement
			(enabled no)
			(sheetname "")
		)
		(fill
			(thermal_gap 0.5)
			(thermal_bridge_width 0.5)
			(island_removal_mode 0)
		)
		(polygon
			(pts
				(xy 342.893142 -334.007968) (xy 343.135458 -334.007968) (xy 343.135458 -333.962502) (xy 343.68232 -333.962502)
				(xy 343.68232 -333.669386) (xy 343.133172 -333.669386) (xy 343.133172 -333.448914) (xy 342.437466 -333.448914)
				(xy 342.437466 -333.575914) (xy 342.893142 -333.575914)
			)
		)
	)
	(zone
		(layer "F.Cu")
		(hatch none 0.5)
		(connect_pads
			(clearance 0)
		)
		(min_thickness 0.25)
		(keepout
			(tracks allowed)
			(vias allowed)
			(pads allowed)
			(copperpour allowed)
			(footprints allowed)
		)
		(placement
			(enabled no)
			(sheetname "")
		)
		(fill
			(thermal_gap 0.5)
			(thermal_bridge_width 0.5)
			(island_removal_mode 0)
		)
		(polygon
			(pts
				(xy 192.066926 -219.726256) (xy 194.098926 -219.726256) (xy 194.098926 -219.954856) (xy 192.066926 -219.954856)
				(xy 191.935608 -219.954856) (xy 191.9097 -219.954856) (xy 191.9097 -219.726256) (xy 191.935608 -219.726256)
			)
		)
	)
	(zone
		(layer "F.Cu")
		(hatch none 0.5)
		(connect_pads
			(clearance 0)
		)
		(min_thickness 0.25)
		(keepout
			(tracks allowed)
			(vias allowed)
			(pads allowed)
			(copperpour allowed)
			(footprints not_allowed)
		)
		(placement
			(enabled no)
			(sheetname "")
		)
		(fill
			(thermal_gap 0.5)
			(thermal_bridge_width 0.5)
			(island_removal_mode 0)
		)
		(polygon
			(pts
				(arc
					(start 463.281268 -30.154626)
					(mid 464.76301 -29.700014)
					(end 466.240114 -30.169358)
				)
				(arc
					(start 466.240114 -30.169358)
					(mid 468.736982 -29.264211)
					(end 470.799922 -27.591512)
				)
				(arc
					(start 470.799922 -17.008602)
					(mid 457.855452 -18.328426)
					(end 463.281268 -30.154626)
				)
			)
		)
	)
	(zone
		(layer "F.Cu")
		(hatch none 0.5)
		(connect_pads
			(clearance 0)
		)
		(min_thickness 0.25)
		(keepout
			(tracks allowed)
			(vias allowed)
			(pads allowed)
			(copperpour allowed)
			(footprints allowed)
		)
		(placement
			(enabled no)
			(sheetname "")
		)
		(fill
			(thermal_gap 0.5)
			(thermal_bridge_width 0.5)
			(island_removal_mode 0)
		)
		(polygon
			(pts
				(xy 277.58771 -240.022888) (xy 279.912826 -240.022888) (xy 279.981406 -240.022888) (xy 279.981406 -240.934494)
				(xy 277.452836 -240.934494) (xy 277.452836 -240.022888)
			)
		)
	)
	(zone
		(layer "F.Cu")
		(hatch none 0.5)
		(connect_pads
			(clearance 0)
		)
		(min_thickness 0.25)
		(keepout
			(tracks allowed)
			(vias allowed)
			(pads allowed)
			(copperpour allowed)
			(footprints allowed)
		)
		(placement
			(enabled no)
			(sheetname "")
		)
		(fill
			(thermal_gap 0.5)
			(thermal_bridge_width 0.5)
			(island_removal_mode 0)
		)
		(polygon
			(pts
				(xy 11.11631 -219.216478) (xy 11.11631 -218.77274) (xy 13.441426 -218.77274) (xy 13.441426 -219.216478)
			)
		)
	)
	(zone
		(layer "F.Cu")
		(hatch none 0.5)
		(connect_pads
			(clearance 0)
		)
		(min_thickness 0.25)
		(keepout
			(tracks allowed)
			(vias allowed)
			(pads allowed)
			(copperpour allowed)
			(footprints not_allowed)
		)
		(placement
			(enabled no)
			(sheetname "")
		)
		(fill
			(thermal_gap 0.5)
			(thermal_bridge_width 0.5)
			(island_removal_mode 0)
		)
		(polygon
			(pts
				(arc
					(start 366.298734 -435.600094)
					(mid 371.298724 -430.600104)
					(end 376.298714 -435.600094)
				)
				(arc
					(start 376.298714 -435.600094)
					(mid 371.298724 -440.600084)
					(end 366.298734 -435.600094)
				)
			)
		)
	)
	(zone
		(layer "F.Cu")
		(hatch none 0.5)
		(connect_pads
			(clearance 0)
		)
		(min_thickness 0.25)
		(keepout
			(tracks allowed)
			(vias allowed)
			(pads allowed)
			(copperpour allowed)
			(footprints allowed)
		)
		(placement
			(enabled no)
			(sheetname "")
		)
		(fill
			(thermal_gap 0.5)
			(thermal_bridge_width 0.5)
			(island_removal_mode 0)
		)
		(polygon
			(pts
				(xy 161.891726 -231.62641) (xy 163.923726 -231.62641) (xy 164.133276 -231.62641) (xy 164.133276 -232.186988)
				(xy 161.708592 -232.186988) (xy 161.708592 -231.85501) (xy 161.708592 -231.62641) (xy 161.755582 -231.62641)
			)
		)
	)
	(zone
		(layer "F.Cu")
		(hatch none 0.5)
		(connect_pads
			(clearance 0)
		)
		(min_thickness 0.25)
		(keepout
			(tracks allowed)
			(vias allowed)
			(pads allowed)
			(copperpour allowed)
			(footprints allowed)
		)
		(placement
			(enabled no)
			(sheetname "")
		)
		(fill
			(thermal_gap 0.5)
			(thermal_bridge_width 0.5)
			(island_removal_mode 0)
		)
		(polygon
			(pts
				(xy 210.598258 -264.15492) (xy 210.598258 -263.92632) (xy 212.630258 -263.92632) (xy 212.630258 -264.15492)
			)
		)
	)
	(zone
		(layer "F.Cu")
		(hatch none 0.5)
		(connect_pads
			(clearance 0)
		)
		(min_thickness 0.25)
		(keepout
			(tracks allowed)
			(vias allowed)
			(pads allowed)
			(copperpour allowed)
			(footprints allowed)
		)
		(placement
			(enabled no)
			(sheetname "")
		)
		(fill
			(thermal_gap 0.5)
			(thermal_bridge_width 0.5)
			(island_removal_mode 0)
		)
		(polygon
			(pts
				(xy 174.662592 -353.424744) (xy 171.126912 -353.424744) (xy 171.126912 -351.341944) (xy 174.662592 -351.341944)
			)
		)
	)
	(zone
		(layer "F.Cu")
		(hatch none 0.5)
		(connect_pads
			(clearance 0)
		)
		(min_thickness 0.25)
		(keepout
			(tracks allowed)
			(vias allowed)
			(pads allowed)
			(copperpour allowed)
			(footprints allowed)
		)
		(placement
			(enabled no)
			(sheetname "")
		)
		(fill
			(thermal_gap 0.5)
			(thermal_bridge_width 0.5)
			(island_removal_mode 0)
		)
		(polygon
			(pts
				(xy 157.575504 -252.918722) (xy 157.575504 -239.33531) (xy 157.318456 -239.33531) (xy 157.224984 -239.241838)
				(xy 157.224984 -238.787686) (xy 157.317694 -238.694976) (xy 157.575504 -238.694976) (xy 157.575504 -237.080298)
				(xy 157.122114 -237.080298) (xy 156.8069 -236.765084) (xy 156.8069 -235.869988) (xy 156.948378 -235.72851)
				(xy 157.575504 -235.72851) (xy 157.575504 -235.45927) (xy 156.721048 -234.604814) (xy 156.721048 -233.628438)
				(xy 157.575504 -232.773982) (xy 157.575504 -218.348306) (xy 156.972762 -218.348306) (xy 156.83611 -218.211654)
				(xy 156.83611 -218.210638) (xy 156.398976 -218.210638) (xy 155.674314 -217.485976) (xy 155.674314 -216.963752)
				(xy 156.1338 -216.504266) (xy 156.1338 -216.106502) (xy 157.014164 -215.226138) (xy 157.575504 -215.226138)
				(xy 157.575504 -209.42173) (xy 156.962856 -208.809082) (xy 156.962856 -208.042002) (xy 156.962856 -206.597504)
				(xy 156.962856 -206.36992) (xy 156.962856 -204.818996) (xy 156.962856 -204.141324) (xy 157.120336 -203.983844)
				(xy 157.575504 -203.983844) (xy 157.575504 -200.575418) (xy 157.197806 -200.575418) (xy 157.067504 -200.445116)
				(xy 157.067504 -199.17537) (xy 157.575504 -199.17537) (xy 157.575504 -198.419974) (xy 157.031944 -198.419974)
				(xy 156.972762 -198.360792) (xy 156.972762 -198.064628) (xy 156.98978 -198.04761) (xy 156.98978 -197.346316)
				(xy 157.262322 -197.073774) (xy 157.575504 -197.073774) (xy 157.575504 -194.7418) (xy 157.927548 -194.389756)
				(xy 215.32977 -194.389756) (xy 216.10447 -195.164456) (xy 216.10447 -252.7427) (xy 215.47074 -253.37643)
				(xy 158.033212 -253.37643)
			)
		)
	)
	(zone
		(layer "F.Cu")
		(hatch none 0.5)
		(connect_pads
			(clearance 0)
		)
		(min_thickness 0.25)
		(keepout
			(tracks allowed)
			(vias allowed)
			(pads allowed)
			(copperpour allowed)
			(footprints allowed)
		)
		(placement
			(enabled no)
			(sheetname "")
		)
		(fill
			(thermal_gap 0.5)
			(thermal_bridge_width 0.5)
			(island_removal_mode 0)
		)
		(polygon
			(pts
				(xy 413.275526 -207.204818) (xy 413.275526 -206.976218) (xy 415.307526 -206.976218) (xy 415.307526 -207.204818)
			)
		)
	)
	(zone
		(layer "F.Cu")
		(hatch none 0.5)
		(connect_pads
			(clearance 0)
		)
		(min_thickness 0.25)
		(keepout
			(tracks allowed)
			(vias allowed)
			(pads allowed)
			(copperpour allowed)
			(footprints allowed)
		)
		(placement
			(enabled no)
			(sheetname "")
		)
		(fill
			(thermal_gap 0.5)
			(thermal_bridge_width 0.5)
			(island_removal_mode 0)
		)
		(polygon
			(pts
				(xy 41.29151 -239.616488) (xy 41.29151 -239.17275) (xy 43.616626 -239.17275) (xy 43.616626 -239.616488)
			)
		)
	)
	(zone
		(layer "F.Cu")
		(hatch none 0.5)
		(connect_pads
			(clearance 0)
		)
		(min_thickness 0.25)
		(keepout
			(tracks allowed)
			(vias allowed)
			(pads allowed)
			(copperpour allowed)
			(footprints allowed)
		)
		(placement
			(enabled no)
			(sheetname "")
		)
		(fill
			(thermal_gap 0.5)
			(thermal_bridge_width 0.5)
			(island_removal_mode 0)
		)
		(polygon
			(pts
				(xy 192.066926 -287.726374) (xy 194.098926 -287.726374) (xy 194.098926 -287.954974) (xy 192.066926 -287.954974)
				(xy 191.930782 -287.954974) (xy 191.883792 -287.954974) (xy 191.883792 -287.726374) (xy 191.930782 -287.726374)
			)
		)
	)
	(zone
		(layer "F.Cu")
		(hatch none 0.5)
		(connect_pads
			(clearance 0)
		)
		(min_thickness 0.25)
		(keepout
			(tracks allowed)
			(vias allowed)
			(pads allowed)
			(copperpour allowed)
			(footprints allowed)
		)
		(placement
			(enabled no)
			(sheetname "")
		)
		(fill
			(thermal_gap 0.5)
			(thermal_bridge_width 0.5)
			(island_removal_mode 0)
		)
		(polygon
			(pts
				(xy 165.335458 -214.85479) (xy 165.335458 -214.62619) (xy 167.367458 -214.62619) (xy 167.367458 -214.85479)
			)
		)
	)
	(zone
		(layer "F.Cu")
		(hatch none 0.5)
		(connect_pads
			(clearance 0)
		)
		(min_thickness 0.25)
		(keepout
			(tracks allowed)
			(vias allowed)
			(pads allowed)
			(copperpour allowed)
			(footprints allowed)
		)
		(placement
			(enabled no)
			(sheetname "")
		)
		(fill
			(thermal_gap 0.5)
			(thermal_bridge_width 0.5)
			(island_removal_mode 0)
		)
		(polygon
			(pts
				(xy 192.066926 -314.076334) (xy 194.098926 -314.076334) (xy 194.098926 -314.304934) (xy 192.066926 -314.304934)
				(xy 191.930782 -314.304934) (xy 191.883792 -314.304934) (xy 191.883792 -314.076334) (xy 191.930782 -314.076334)
			)
		)
	)
	(zone
		(layer "F.Cu")
		(hatch none 0.5)
		(connect_pads
			(clearance 0)
		)
		(min_thickness 0.25)
		(keepout
			(tracks allowed)
			(vias allowed)
			(pads allowed)
			(copperpour allowed)
			(footprints allowed)
		)
		(placement
			(enabled no)
			(sheetname "")
		)
		(fill
			(thermal_gap 0.5)
			(thermal_bridge_width 0.5)
			(island_removal_mode 0)
		)
		(polygon
			(pts
				(xy 135.95604 -216.916508) (xy 136.24306 -216.916508) (xy 136.27354 -216.886028) (xy 136.27354 -216.258648)
				(xy 136.18718 -216.172288) (xy 135.99922 -216.172288) (xy 135.92556 -216.245948) (xy 135.92556 -216.886028)
			)
		)
	)
	(zone
		(layer "F.Cu")
		(hatch none 0.5)
		(connect_pads
			(clearance 0)
		)
		(min_thickness 0.25)
		(keepout
			(tracks allowed)
			(vias allowed)
			(pads allowed)
			(copperpour allowed)
			(footprints allowed)
		)
		(placement
			(enabled no)
			(sheetname "")
		)
		(fill
			(thermal_gap 0.5)
			(thermal_bridge_width 0.5)
			(island_removal_mode 0)
		)
		(polygon
			(pts
				(xy 127.170688 -410.948886) (xy 127.170688 -406.105868) (xy 129.055114 -406.105868) (xy 129.055114 -410.948886)
			)
		)
	)
	(zone
		(layer "F.Cu")
		(hatch none 0.5)
		(connect_pads
			(clearance 0)
		)
		(min_thickness 0.25)
		(keepout
			(tracks allowed)
			(vias allowed)
			(pads allowed)
			(copperpour allowed)
			(footprints allowed)
		)
		(placement
			(enabled no)
			(sheetname "")
		)
		(fill
			(thermal_gap 0.5)
			(thermal_bridge_width 0.5)
			(island_removal_mode 0)
		)
		(polygon
			(pts
				(xy 274.143978 -285.516574) (xy 274.143978 -285.072836) (xy 276.469094 -285.072836) (xy 276.469094 -285.516574)
			)
		)
	)
	(zone
		(layer "F.Cu")
		(hatch none 0.5)
		(connect_pads
			(clearance 0)
		)
		(min_thickness 0.25)
		(keepout
			(tracks allowed)
			(vias allowed)
			(pads allowed)
			(copperpour allowed)
			(footprints allowed)
		)
		(placement
			(enabled no)
			(sheetname "")
		)
		(fill
			(thermal_gap 0.5)
			(thermal_bridge_width 0.5)
			(island_removal_mode 0)
		)
		(polygon
			(pts
				(xy 157.791658 -205.504796) (xy 157.791658 -205.276196) (xy 159.823658 -205.276196) (xy 159.823658 -205.504796)
			)
		)
	)
	(zone
		(layer "F.Cu")
		(hatch none 0.5)
		(connect_pads
			(clearance 0)
		)
		(min_thickness 0.25)
		(keepout
			(tracks allowed)
			(vias allowed)
			(pads allowed)
			(copperpour allowed)
			(footprints allowed)
		)
		(placement
			(enabled no)
			(sheetname "")
		)
		(fill
			(thermal_gap 0.5)
			(thermal_bridge_width 0.5)
			(island_removal_mode 0)
		)
		(polygon
			(pts
				(xy 262.50011 -314.41644) (xy 262.50011 -313.972702) (xy 264.825226 -313.972702) (xy 264.825226 -314.41644)
			)
		)
	)
	(zone
		(layer "F.Cu")
		(hatch none 0.5)
		(connect_pads
			(clearance 0)
		)
		(min_thickness 0.25)
		(keepout
			(tracks allowed)
			(vias allowed)
			(pads allowed)
			(copperpour allowed)
			(footprints allowed)
		)
		(placement
			(enabled no)
			(sheetname "")
		)
		(fill
			(thermal_gap 0.5)
			(thermal_bridge_width 0.5)
			(island_removal_mode 0)
		)
		(polygon
			(pts
				(xy 88.82888 -339.369146) (xy 87.08136 -339.369146) (xy 87.08136 -337.433666) (xy 88.82888 -337.433666)
			)
		)
	)
	(zone
		(layer "F.Cu")
		(hatch none 0.5)
		(connect_pads
			(clearance 0)
		)
		(min_thickness 0.25)
		(keepout
			(tracks allowed)
			(vias allowed)
			(pads allowed)
			(copperpour allowed)
			(footprints allowed)
		)
		(placement
			(enabled no)
			(sheetname "")
		)
		(fill
			(thermal_gap 0.5)
			(thermal_bridge_width 0.5)
			(island_removal_mode 0)
		)
		(polygon
			(pts
				(xy 337.44916 -289.006788) (xy 337.73618 -289.006788) (xy 337.76666 -288.976308) (xy 337.76666 -288.348928)
				(xy 337.6803 -288.262568) (xy 337.49234 -288.262568) (xy 337.41868 -288.336228) (xy 337.41868 -288.976308)
			)
		)
	)
	(zone
		(layer "F.Cu")
		(hatch none 0.5)
		(connect_pads
			(clearance 0)
		)
		(min_thickness 0.25)
		(keepout
			(tracks allowed)
			(vias allowed)
			(pads allowed)
			(copperpour allowed)
			(footprints allowed)
		)
		(placement
			(enabled no)
			(sheetname "")
		)
		(fill
			(thermal_gap 0.5)
			(thermal_bridge_width 0.5)
			(island_removal_mode 0)
		)
		(polygon
			(pts
				(xy 176.979326 -239.276382) (xy 179.011326 -239.276382) (xy 179.011326 -239.504982) (xy 176.979326 -239.504982)
				(xy 176.843182 -239.504982) (xy 176.796192 -239.504982) (xy 176.796192 -239.276382) (xy 176.843182 -239.276382)
			)
		)
	)
	(zone
		(layer "F.Cu")
		(hatch none 0.5)
		(connect_pads
			(clearance 0)
		)
		(min_thickness 0.25)
		(keepout
			(tracks allowed)
			(vias allowed)
			(pads allowed)
			(copperpour allowed)
			(footprints allowed)
		)
		(placement
			(enabled no)
			(sheetname "")
		)
		(fill
			(thermal_gap 0.5)
			(thermal_bridge_width 0.5)
			(island_removal_mode 0)
		)
		(polygon
			(pts
				(xy 44.735242 -205.616556) (xy 44.735242 -205.172818) (xy 47.060358 -205.172818) (xy 47.060358 -205.616556)
			)
		)
	)
	(zone
		(layer "F.Cu")
		(hatch none 0.5)
		(connect_pads
			(clearance 0)
		)
		(min_thickness 0.25)
		(keepout
			(tracks allowed)
			(vias allowed)
			(pads allowed)
			(copperpour allowed)
			(footprints allowed)
		)
		(placement
			(enabled no)
			(sheetname "")
		)
		(fill
			(thermal_gap 0.5)
			(thermal_bridge_width 0.5)
			(island_removal_mode 0)
		)
		(polygon
			(pts
				(xy 180.423058 -211.455) (xy 180.423058 -211.2264) (xy 182.455058 -211.2264) (xy 182.455058 -211.455)
			)
		)
	)
	(zone
		(layer "F.Cu")
		(hatch none 0.5)
		(connect_pads
			(clearance 0)
		)
		(min_thickness 0.25)
		(keepout
			(tracks allowed)
			(vias allowed)
			(pads allowed)
			(copperpour allowed)
			(footprints allowed)
		)
		(placement
			(enabled no)
			(sheetname "")
		)
		(fill
			(thermal_gap 0.5)
			(thermal_bridge_width 0.5)
			(island_removal_mode 0)
		)
		(polygon
			(pts
				(xy 262.50011 -202.216512) (xy 262.50011 -201.772774) (xy 264.825226 -201.772774) (xy 264.825226 -202.216512)
			)
		)
	)
	(zone
		(layer "F.Cu")
		(hatch none 0.5)
		(connect_pads
			(clearance 0)
		)
		(min_thickness 0.25)
		(keepout
			(tracks allowed)
			(vias allowed)
			(pads allowed)
			(copperpour allowed)
			(footprints allowed)
		)
		(placement
			(enabled no)
			(sheetname "")
		)
		(fill
			(thermal_gap 0.5)
			(thermal_bridge_width 0.5)
			(island_removal_mode 0)
		)
		(polygon
			(pts
				(xy 262.50011 -226.86645) (xy 262.50011 -226.422712) (xy 264.825226 -226.422712) (xy 264.825226 -226.86645)
			)
		)
	)
	(zone
		(layer "F.Cu")
		(hatch none 0.5)
		(connect_pads
			(clearance 0)
		)
		(min_thickness 0.25)
		(keepout
			(tracks allowed)
			(vias allowed)
			(pads allowed)
			(copperpour allowed)
			(footprints allowed)
		)
		(placement
			(enabled no)
			(sheetname "")
		)
		(fill
			(thermal_gap 0.5)
			(thermal_bridge_width 0.5)
			(island_removal_mode 0)
		)
		(polygon
			(pts
				(xy 388.2517 -26.45664) (xy 388.2517 -24.91486) (xy 390.2456 -24.91486) (xy 390.2456 -26.45664)
			)
		)
	)
	(zone
		(layer "F.Cu")
		(hatch none 0.5)
		(connect_pads
			(clearance 0)
		)
		(min_thickness 0.25)
		(keepout
			(tracks allowed)
			(vias allowed)
			(pads allowed)
			(copperpour allowed)
			(footprints allowed)
		)
		(placement
			(enabled no)
			(sheetname "")
		)
		(fill
			(thermal_gap 0.5)
			(thermal_bridge_width 0.5)
			(island_removal_mode 0)
		)
		(polygon
			(pts
				(xy 353.089718 -335.958942) (xy 351.342198 -335.958942) (xy 351.342198 -334.023462) (xy 353.089718 -334.023462)
			)
		)
	)
	(zone
		(layer "F.Cu")
		(hatch none 0.5)
		(connect_pads
			(clearance 0)
		)
		(min_thickness 0.25)
		(keepout
			(tracks allowed)
			(vias allowed)
			(pads allowed)
			(copperpour allowed)
			(footprints allowed)
		)
		(placement
			(enabled no)
			(sheetname "")
		)
		(fill
			(thermal_gap 0.5)
			(thermal_bridge_width 0.5)
			(island_removal_mode 0)
		)
		(polygon
			(pts
				(xy 52.65674 -165.105588) (xy 52.65674 -163.358068) (xy 54.59222 -163.358068) (xy 54.59222 -165.105588)
			)
		)
	)
	(zone
		(layer "F.Cu")
		(hatch none 0.5)
		(connect_pads
			(clearance 0)
		)
		(min_thickness 0.25)
		(keepout
			(tracks allowed)
			(vias allowed)
			(pads allowed)
			(copperpour allowed)
			(footprints allowed)
		)
		(placement
			(enabled no)
			(sheetname "")
		)
		(fill
			(thermal_gap 0.5)
			(thermal_bridge_width 0.5)
			(island_removal_mode 0)
		)
		(polygon
			(pts
				(xy 210.598258 -295.604946) (xy 210.598258 -295.376346) (xy 212.630258 -295.376346) (xy 212.630258 -295.604946)
			)
		)
	)
	(zone
		(layer "F.Cu")
		(hatch none 0.5)
		(connect_pads
			(clearance 0)
		)
		(min_thickness 0.25)
		(keepout
			(tracks allowed)
			(vias allowed)
			(pads allowed)
			(copperpour allowed)
			(footprints allowed)
		)
		(placement
			(enabled no)
			(sheetname "")
		)
		(fill
			(thermal_gap 0.5)
			(thermal_bridge_width 0.5)
			(island_removal_mode 0)
		)
		(polygon
			(pts
				(xy 167.367458 -236.954822) (xy 165.335458 -236.954822) (xy 164.910262 -236.954822) (xy 164.910262 -235.891324)
				(xy 167.765476 -235.891324) (xy 167.765476 -236.954822)
			)
		)
	)
	(zone
		(layer "F.Cu")
		(hatch none 0.5)
		(connect_pads
			(clearance 0)
		)
		(min_thickness 0.25)
		(keepout
			(tracks allowed)
			(vias allowed)
			(pads allowed)
			(copperpour allowed)
			(footprints allowed)
		)
		(placement
			(enabled no)
			(sheetname "")
		)
		(fill
			(thermal_gap 0.5)
			(thermal_bridge_width 0.5)
			(island_removal_mode 0)
		)
		(polygon
			(pts
				(xy 14.838426 -104.777286) (xy 14.838426 -103.812086) (xy 17.032986 -103.812086) (xy 17.032986 -104.777286)
			)
		)
	)
	(zone
		(layer "F.Cu")
		(hatch none 0.5)
		(connect_pads
			(clearance 0)
		)
		(min_thickness 0.25)
		(keepout
			(tracks allowed)
			(vias allowed)
			(pads allowed)
			(copperpour allowed)
			(footprints allowed)
		)
		(placement
			(enabled no)
			(sheetname "")
		)
		(fill
			(thermal_gap 0.5)
			(thermal_bridge_width 0.5)
			(island_removal_mode 0)
		)
		(polygon
			(pts
				(xy 107.796584 -333.586582) (xy 104.260904 -333.586582) (xy 104.260904 -331.503782) (xy 107.796584 -331.503782)
			)
		)
	)
	(zone
		(layer "F.Cu")
		(hatch none 0.5)
		(connect_pads
			(clearance 0)
		)
		(min_thickness 0.25)
		(keepout
			(tracks allowed)
			(vias allowed)
			(pads allowed)
			(copperpour allowed)
			(footprints allowed)
		)
		(placement
			(enabled no)
			(sheetname "")
		)
		(fill
			(thermal_gap 0.5)
			(thermal_bridge_width 0.5)
			(island_removal_mode 0)
		)
		(polygon
			(pts
				(xy 259.056378 -216.666572) (xy 259.056378 -216.222834) (xy 261.381494 -216.222834) (xy 261.381494 -216.666572)
			)
		)
	)
	(zone
		(layer "F.Cu")
		(hatch none 0.5)
		(connect_pads
			(clearance 0)
		)
		(min_thickness 0.25)
		(keepout
			(tracks allowed)
			(vias allowed)
			(pads allowed)
			(copperpour allowed)
			(footprints allowed)
		)
		(placement
			(enabled no)
			(sheetname "")
		)
		(fill
			(thermal_gap 0.5)
			(thermal_bridge_width 0.5)
			(island_removal_mode 0)
		)
		(polygon
			(pts
				(xy 59.822842 -293.166546) (xy 59.822842 -292.722808) (xy 62.147958 -292.722808) (xy 62.147958 -293.166546)
			)
		)
	)
	(zone
		(layer "F.Cu")
		(hatch none 0.5)
		(connect_pads
			(clearance 0)
		)
		(min_thickness 0.25)
		(keepout
			(tracks allowed)
			(vias allowed)
			(pads allowed)
			(copperpour allowed)
			(footprints allowed)
		)
		(placement
			(enabled no)
			(sheetname "")
		)
		(fill
			(thermal_gap 0.5)
			(thermal_bridge_width 0.5)
			(island_removal_mode 0)
		)
		(polygon
			(pts
				(xy 165.335458 -316.004956) (xy 165.335458 -315.776356) (xy 167.367458 -315.776356) (xy 167.367458 -316.004956)
			)
		)
	)
	(zone
		(layer "F.Cu")
		(hatch none 0.5)
		(connect_pads
			(clearance 0)
		)
		(min_thickness 0.25)
		(keepout
			(tracks allowed)
			(vias allowed)
			(pads allowed)
			(copperpour allowed)
			(footprints allowed)
		)
		(placement
			(enabled no)
			(sheetname "")
		)
		(fill
			(thermal_gap 0.5)
			(thermal_bridge_width 0.5)
			(island_removal_mode 0)
		)
		(polygon
			(pts
				(xy 169.92854 -343.172288) (xy 169.92854 -339.809328) (xy 174.15002 -339.809328) (xy 174.15002 -343.172288)
			)
		)
	)
	(zone
		(layer "F.Cu")
		(hatch none 0.5)
		(connect_pads
			(clearance 0)
		)
		(min_thickness 0.25)
		(keepout
			(tracks allowed)
			(vias allowed)
			(pads allowed)
			(copperpour allowed)
			(footprints allowed)
		)
		(placement
			(enabled no)
			(sheetname "")
		)
		(fill
			(thermal_gap 0.5)
			(thermal_bridge_width 0.5)
			(island_removal_mode 0)
		)
		(polygon
			(pts
				(xy 176.979326 -304.72634) (xy 179.011326 -304.72634) (xy 179.011326 -304.95494) (xy 176.979326 -304.95494)
				(xy 176.843182 -304.95494) (xy 176.796192 -304.95494) (xy 176.796192 -304.72634) (xy 176.843182 -304.72634)
			)
		)
	)
	(zone
		(layer "F.Cu")
		(hatch none 0.5)
		(connect_pads
			(clearance 0)
		)
		(min_thickness 0.25)
		(keepout
			(tracks allowed)
			(vias allowed)
			(pads allowed)
			(copperpour allowed)
			(footprints allowed)
		)
		(placement
			(enabled no)
			(sheetname "")
		)
		(fill
			(thermal_gap 0.5)
			(thermal_bridge_width 0.5)
			(island_removal_mode 0)
		)
		(polygon
			(pts
				(xy 11.11631 -272.766536) (xy 11.11631 -272.322798) (xy 13.441426 -272.322798) (xy 13.441426 -272.766536)
			)
		)
	)
	(zone
		(layer "F.Cu")
		(hatch none 0.5)
		(connect_pads
			(clearance 0)
		)
		(min_thickness 0.25)
		(keepout
			(tracks allowed)
			(vias allowed)
			(pads allowed)
			(copperpour allowed)
			(footprints allowed)
		)
		(placement
			(enabled no)
			(sheetname "")
		)
		(fill
			(thermal_gap 0.5)
			(thermal_bridge_width 0.5)
			(island_removal_mode 0)
		)
		(polygon
			(pts
				(xy 423.779696 -138.4427) (xy 423.779696 -134.40664) (xy 427.660816 -134.40664) (xy 427.660816 -138.4427)
			)
		)
	)
	(zone
		(layer "F.Cu")
		(hatch none 0.5)
		(connect_pads
			(clearance 0)
		)
		(min_thickness 0.25)
		(keepout
			(tracks not_allowed)
			(vias allowed)
			(pads allowed)
			(copperpour not_allowed)
			(footprints allowed)
		)
		(placement
			(enabled no)
			(sheetname "")
		)
		(fill
			(thermal_gap 0.5)
			(thermal_bridge_width 0.5)
			(island_removal_mode 0)
		)
		(polygon
			(pts
				(xy 437.568848 -11.992356) (xy 437.744108 -11.992356) (xy 437.772048 -11.964416) (xy 437.772048 -10.569956)
				(xy 437.749188 -10.547096) (xy 437.579008 -10.547096) (xy 437.558688 -10.567416) (xy 437.558688 -11.982196)
			)
		)
	)
	(zone
		(layer "F.Cu")
		(hatch none 0.5)
		(connect_pads
			(clearance 0)
		)
		(min_thickness 0.25)
		(keepout
			(tracks allowed)
			(vias allowed)
			(pads allowed)
			(copperpour allowed)
			(footprints allowed)
		)
		(placement
			(enabled no)
			(sheetname "")
		)
		(fill
			(thermal_gap 0.5)
			(thermal_bridge_width 0.5)
			(island_removal_mode 0)
		)
		(polygon
			(pts
				(xy 140.249148 -244.867176) (xy 140.631418 -244.867176) (xy 142.655798 -242.842542) (xy 144.570196 -242.842542)
				(xy 145.891504 -241.521234) (xy 146.315684 -241.521234) (xy 146.315684 -241.520472) (xy 146.356578 -241.520472)
				(xy 146.356578 -240.860834) (xy 146.950684 -240.860834) (xy 147.022312 -240.860834) (xy 147.022312 -240.400332)
				(xy 147.355814 -240.06683) (xy 147.355814 -239.973104) (xy 147.355814 -239.012222) (xy 147.941284 -238.426752)
				(xy 148.025612 -238.342424) (xy 148.025612 -235.950506) (xy 148.246084 -235.730034) (xy 148.319998 -235.65612)
				(xy 148.319998 -234.74172) (xy 148.550884 -234.510834) (xy 148.644102 -234.417616) (xy 148.135086 -233.9086)
				(xy 148.041868 -234.001818) (xy 145.947892 -236.09554) (xy 145.94078 -236.102652) (xy 142.990062 -239.05337)
				(xy 141.165834 -239.05337) (xy 141.127988 -239.091216) (xy 140.927582 -239.091216) (xy 140.267182 -239.751616)
				(xy 140.267182 -239.886744) (xy 140.502894 -240.122456) (xy 140.502894 -240.207546) (xy 140.257022 -240.453418)
				(xy 140.257022 -240.54054) (xy 140.786612 -241.07013) (xy 140.832332 -241.07013) (xy 141.53642 -240.366042)
				(xy 141.960346 -240.366042) (xy 142.014194 -240.41989) (xy 142.014194 -240.983008) (xy 141.982444 -241.014758)
				(xy 141.70279 -241.014758) (xy 140.64361 -242.073938) (xy 140.64361 -242.115086) (xy 140.982954 -242.45443)
				(xy 140.982954 -242.614958) (xy 140.249148 -243.348764)
			)
		)
	)
	(zone
		(layer "F.Cu")
		(hatch none 0.5)
		(connect_pads
			(clearance 0)
		)
		(min_thickness 0.25)
		(keepout
			(tracks allowed)
			(vias allowed)
			(pads allowed)
			(copperpour allowed)
			(footprints allowed)
		)
		(placement
			(enabled no)
			(sheetname "")
		)
		(fill
			(thermal_gap 0.5)
			(thermal_bridge_width 0.5)
			(island_removal_mode 0)
		)
		(polygon
			(pts
				(xy 406.007824 -410.948886) (xy 406.007824 -406.105868) (xy 407.89225 -406.105868) (xy 407.89225 -410.948886)
			)
		)
	)
	(zone
		(layer "F.Cu")
		(hatch none 0.5)
		(connect_pads
			(clearance 0)
		)
		(min_thickness 0.25)
		(keepout
			(tracks allowed)
			(vias allowed)
			(pads allowed)
			(copperpour allowed)
			(footprints allowed)
		)
		(placement
			(enabled no)
			(sheetname "")
		)
		(fill
			(thermal_gap 0.5)
			(thermal_bridge_width 0.5)
			(island_removal_mode 0)
		)
		(polygon
			(pts
				(xy 14.560042 -295.716452) (xy 14.560042 -295.272714) (xy 16.885158 -295.272714) (xy 16.885158 -295.716452)
			)
		)
	)
	(zone
		(layer "F.Cu")
		(hatch none 0.5)
		(connect_pads
			(clearance 0)
		)
		(min_thickness 0.25)
		(keepout
			(tracks allowed)
			(vias allowed)
			(pads allowed)
			(copperpour allowed)
			(footprints allowed)
		)
		(placement
			(enabled no)
			(sheetname "")
		)
		(fill
			(thermal_gap 0.5)
			(thermal_bridge_width 0.5)
			(island_removal_mode 0)
		)
		(polygon
			(pts
				(xy 157.791658 -217.40495) (xy 157.791658 -217.17635) (xy 159.823658 -217.17635) (xy 159.823658 -217.40495)
			)
		)
	)
	(zone
		(layer "F.Cu")
		(hatch none 0.5)
		(connect_pads
			(clearance 0)
		)
		(min_thickness 0.25)
		(keepout
			(tracks allowed)
			(vias allowed)
			(pads allowed)
			(copperpour allowed)
			(footprints allowed)
		)
		(placement
			(enabled no)
			(sheetname "")
		)
		(fill
			(thermal_gap 0.5)
			(thermal_bridge_width 0.5)
			(island_removal_mode 0)
		)
		(polygon
			(pts
				(xy 176.979326 -251.176282) (xy 179.011326 -251.176282) (xy 179.011326 -251.404882) (xy 176.979326 -251.404882)
				(xy 176.812702 -251.404882) (xy 176.812702 -251.176282)
			)
		)
	)
	(zone
		(layer "F.Cu")
		(hatch none 0.5)
		(connect_pads
			(clearance 0)
		)
		(min_thickness 0.25)
		(keepout
			(tracks allowed)
			(vias allowed)
			(pads allowed)
			(copperpour allowed)
			(footprints allowed)
		)
		(placement
			(enabled no)
			(sheetname "")
		)
		(fill
			(thermal_gap 0.5)
			(thermal_bridge_width 0.5)
			(island_removal_mode 0)
		)
		(polygon
			(pts
				(xy 53.891688 -353.418394) (xy 50.356008 -353.418394) (xy 50.356008 -351.335594) (xy 53.891688 -351.335594)
			)
		)
	)
	(zone
		(layer "F.Cu")
		(hatch none 0.5)
		(connect_pads
			(clearance 0)
		)
		(min_thickness 0.25)
		(keepout
			(tracks allowed)
			(vias allowed)
			(pads allowed)
			(copperpour allowed)
			(footprints allowed)
		)
		(placement
			(enabled no)
			(sheetname "")
		)
		(fill
			(thermal_gap 0.5)
			(thermal_bridge_width 0.5)
			(island_removal_mode 0)
		)
		(polygon
			(pts
				(xy 426.2374 -20.04822) (xy 426.2374 -16.913606) (xy 428.016162 -16.913606) (xy 428.016162 -20.04822)
			)
		)
	)
	(zone
		(layer "F.Cu")
		(hatch none 0.5)
		(connect_pads
			(clearance 0)
		)
		(min_thickness 0.25)
		(keepout
			(tracks allowed)
			(vias allowed)
			(pads allowed)
			(copperpour allowed)
			(footprints allowed)
		)
		(placement
			(enabled no)
			(sheetname "")
		)
		(fill
			(thermal_gap 0.5)
			(thermal_bridge_width 0.5)
			(island_removal_mode 0)
		)
		(polygon
			(pts
				(xy 440.006994 -304.72634) (xy 442.038994 -304.72634) (xy 442.038994 -304.95494) (xy 440.006994 -304.95494)
				(xy 439.87085 -304.95494) (xy 439.82386 -304.95494) (xy 439.82386 -304.72634) (xy 439.87085 -304.72634)
			)
		)
	)
	(zone
		(layer "F.Cu")
		(hatch none 0.5)
		(connect_pads
			(clearance 0)
		)
		(min_thickness 0.25)
		(keepout
			(tracks allowed)
			(vias allowed)
			(pads allowed)
			(copperpour allowed)
			(footprints allowed)
		)
		(placement
			(enabled no)
			(sheetname "")
		)
		(fill
			(thermal_gap 0.5)
			(thermal_bridge_width 0.5)
			(island_removal_mode 0)
		)
		(polygon
			(pts
				(xy 59.822842 -247.26646) (xy 59.822842 -246.822722) (xy 62.147958 -246.822722) (xy 62.147958 -247.26646)
			)
		)
	)
	(zone
		(layer "F.Cu")
		(hatch none 0.5)
		(connect_pads
			(clearance 0)
		)
		(min_thickness 0.25)
		(keepout
			(tracks allowed)
			(vias allowed)
			(pads allowed)
			(copperpour allowed)
			(footprints allowed)
		)
		(placement
			(enabled no)
			(sheetname "")
		)
		(fill
			(thermal_gap 0.5)
			(thermal_bridge_width 0.5)
			(island_removal_mode 0)
		)
		(polygon
			(pts
				(xy 55.0291 -150.480268) (xy 55.0291 -146.944588) (xy 57.1119 -146.944588) (xy 57.1119 -150.480268)
			)
		)
	)
	(zone
		(layer "F.Cu")
		(hatch none 0.5)
		(connect_pads
			(clearance 0)
		)
		(min_thickness 0.25)
		(keepout
			(tracks allowed)
			(vias allowed)
			(pads allowed)
			(copperpour allowed)
			(footprints not_allowed)
		)
		(placement
			(enabled no)
			(sheetname "")
		)
		(fill
			(thermal_gap 0.5)
			(thermal_bridge_width 0.5)
			(island_removal_mode 0)
		)
		(polygon
			(pts
				(xy 468.799926 -448.050158) (xy 476.79991 -448.050158) (xy 476.79991 -459.050136) (xy 468.799926 -459.050136)
			)
		)
	)
	(zone
		(layer "F.Cu")
		(hatch none 0.5)
		(connect_pads
			(clearance 0)
		)
		(min_thickness 0.25)
		(keepout
			(tracks allowed)
			(vias allowed)
			(pads allowed)
			(copperpour allowed)
			(footprints allowed)
		)
		(placement
			(enabled no)
			(sheetname "")
		)
		(fill
			(thermal_gap 0.5)
			(thermal_bridge_width 0.5)
			(island_removal_mode 0)
		)
		(polygon
			(pts
				(xy 259.056378 -262.566658) (xy 259.056378 -262.12292) (xy 261.381494 -262.12292) (xy 261.381494 -262.566658)
			)
		)
	)
	(zone
		(layer "F.Cu")
		(hatch none 0.5)
		(connect_pads
			(clearance 0)
		)
		(min_thickness 0.25)
		(keepout
			(tracks allowed)
			(vias allowed)
			(pads allowed)
			(copperpour allowed)
			(footprints allowed)
		)
		(placement
			(enabled no)
			(sheetname "")
		)
		(fill
			(thermal_gap 0.5)
			(thermal_bridge_width 0.5)
			(island_removal_mode 0)
		)
		(polygon
			(pts
				(xy 277.58771 -286.366458) (xy 277.58771 -285.92272) (xy 279.912826 -285.92272) (xy 279.912826 -286.366458)
			)
		)
	)
	(zone
		(layer "F.Cu")
		(hatch none 0.5)
		(connect_pads
			(clearance 0)
		)
		(min_thickness 0.25)
		(keepout
			(tracks allowed)
			(vias allowed)
			(pads allowed)
			(copperpour allowed)
			(footprints allowed)
		)
		(placement
			(enabled no)
			(sheetname "")
		)
		(fill
			(thermal_gap 0.5)
			(thermal_bridge_width 0.5)
			(island_removal_mode 0)
		)
		(polygon
			(pts
				(xy 63.977012 -264.266426) (xy 63.977012 -263.822688) (xy 66.212212 -263.822688) (xy 66.212212 -264.266426)
			)
		)
	)
	(zone
		(layer "F.Cu")
		(hatch none 0.5)
		(connect_pads
			(clearance 0)
		)
		(min_thickness 0.25)
		(keepout
			(tracks allowed)
			(vias allowed)
			(pads allowed)
			(copperpour allowed)
			(footprints not_allowed)
		)
		(placement
			(enabled no)
			(sheetname "")
		)
		(fill
			(thermal_gap 0.5)
			(thermal_bridge_width 0.5)
			(island_removal_mode 0)
		)
		(polygon
			(pts
				(arc
					(start 7.999984 -435.600094)
					(mid 12.999974 -430.600104)
					(end 17.999964 -435.600094)
				)
				(arc
					(start 17.999964 -435.600094)
					(mid 12.999974 -440.600084)
					(end 7.999984 -435.600094)
				)
			)
		)
	)
	(zone
		(layer "F.Cu")
		(hatch none 0.5)
		(connect_pads
			(clearance 0)
		)
		(min_thickness 0.25)
		(keepout
			(tracks allowed)
			(vias allowed)
			(pads allowed)
			(copperpour allowed)
			(footprints allowed)
		)
		(placement
			(enabled no)
			(sheetname "")
		)
		(fill
			(thermal_gap 0.5)
			(thermal_bridge_width 0.5)
			(island_removal_mode 0)
		)
		(polygon
			(pts
				(xy 455.094594 -247.776238) (xy 457.126594 -247.776238) (xy 457.126594 -248.004838) (xy 455.094594 -248.004838)
				(xy 454.92797 -248.004838) (xy 454.92797 -247.776238)
			)
		)
	)
	(zone
		(layer "F.Cu")
		(hatch none 0.5)
		(connect_pads
			(clearance 0)
		)
		(min_thickness 0.25)
		(keepout
			(tracks not_allowed)
			(vias allowed)
			(pads allowed)
			(copperpour not_allowed)
			(footprints allowed)
		)
		(placement
			(enabled no)
			(sheetname "")
		)
		(fill
			(thermal_gap 0.5)
			(thermal_bridge_width 0.5)
			(island_removal_mode 0)
		)
		(polygon
			(pts
				(arc
					(start 231.650032 -272.50009)
					(mid 236.650022 -267.5001)
					(end 241.650012 -272.50009)
				)
				(arc
					(start 241.650012 -272.50009)
					(mid 236.650022 -277.50008)
					(end 231.650032 -272.50009)
				)
			)
		)
	)
	(zone
		(layer "F.Cu")
		(hatch none 0.5)
		(connect_pads
			(clearance 0)
		)
		(min_thickness 0.25)
		(keepout
			(tracks allowed)
			(vias allowed)
			(pads allowed)
			(copperpour allowed)
			(footprints allowed)
		)
		(placement
			(enabled no)
			(sheetname "")
		)
		(fill
			(thermal_gap 0.5)
			(thermal_bridge_width 0.5)
			(island_removal_mode 0)
		)
		(polygon
			(pts
				(xy 11.11631 -222.616522) (xy 11.11631 -222.172784) (xy 13.441426 -222.172784) (xy 13.441426 -222.616522)
			)
		)
	)
	(zone
		(layer "F.Cu")
		(hatch none 0.5)
		(connect_pads
			(clearance 0)
		)
		(min_thickness 0.25)
		(keepout
			(tracks allowed)
			(vias allowed)
			(pads allowed)
			(copperpour allowed)
			(footprints allowed)
		)
		(placement
			(enabled no)
			(sheetname "")
		)
		(fill
			(thermal_gap 0.5)
			(thermal_bridge_width 0.5)
			(island_removal_mode 0)
		)
		(polygon
			(pts
				(xy 357.53548 -215.224868) (xy 357.8225 -215.224868) (xy 357.85298 -215.194388) (xy 357.85298 -214.567008)
				(xy 357.76662 -214.480648) (xy 357.57866 -214.480648) (xy 357.505 -214.554308) (xy 357.505 -215.194388)
			)
		)
	)
	(zone
		(layer "F.Cu")
		(hatch none 0.5)
		(connect_pads
			(clearance 0)
		)
		(min_thickness 0.25)
		(keepout
			(tracks allowed)
			(vias allowed)
			(pads allowed)
			(copperpour allowed)
			(footprints allowed)
		)
		(placement
			(enabled no)
			(sheetname "")
		)
		(fill
			(thermal_gap 0.5)
			(thermal_bridge_width 0.5)
			(island_removal_mode 0)
		)
		(polygon
			(pts
				(xy 29.647642 -215.816434) (xy 29.647642 -215.372696) (xy 31.972758 -215.372696) (xy 31.972758 -215.816434)
			)
		)
	)
	(zone
		(layer "F.Cu")
		(hatch none 0.5)
		(connect_pads
			(clearance 0)
		)
		(min_thickness 0.25)
		(keepout
			(tracks allowed)
			(vias allowed)
			(pads allowed)
			(copperpour allowed)
			(footprints allowed)
		)
		(placement
			(enabled no)
			(sheetname "")
		)
		(fill
			(thermal_gap 0.5)
			(thermal_bridge_width 0.5)
			(island_removal_mode 0)
		)
		(polygon
			(pts
				(xy 409.831794 -306.426362) (xy 411.863794 -306.426362) (xy 411.863794 -306.654962) (xy 409.831794 -306.654962)
				(xy 409.582366 -306.654962) (xy 409.582366 -306.426362)
			)
		)
	)
	(zone
		(layer "F.Cu")
		(hatch none 0.5)
		(connect_pads
			(clearance 0)
		)
		(min_thickness 0.25)
		(keepout
			(tracks allowed)
			(vias allowed)
			(pads allowed)
			(copperpour allowed)
			(footprints allowed)
		)
		(placement
			(enabled no)
			(sheetname "")
		)
		(fill
			(thermal_gap 0.5)
			(thermal_bridge_width 0.5)
			(island_removal_mode 0)
		)
		(polygon
			(pts
				(xy 55.055516 -171.697904) (xy 51.049936 -171.697904) (xy 50.569876 -172.177964) (xy 50.569876 -174.242984)
				(xy 50.841656 -174.514764) (xy 52.695856 -174.514764) (xy 52.947316 -174.766224) (xy 52.947316 -176.686464)
				(xy 53.363876 -177.103024) (xy 54.854856 -177.103024) (xy 55.502556 -176.455324) (xy 55.502556 -172.144944)
			)
		)
	)
	(zone
		(layer "F.Cu")
		(hatch none 0.5)
		(connect_pads
			(clearance 0)
		)
		(min_thickness 0.25)
		(keepout
			(tracks allowed)
			(vias allowed)
			(pads allowed)
			(copperpour allowed)
			(footprints not_allowed)
		)
		(placement
			(enabled no)
			(sheetname "")
		)
		(fill
			(thermal_gap 0.5)
			(thermal_bridge_width 0.5)
			(island_removal_mode 0)
		)
		(polygon
			(pts
				(arc
					(start 230.89997 -81.700116)
					(mid 235.89996 -76.700126)
					(end 240.89995 -81.700116)
				)
				(arc
					(start 240.89995 -81.700116)
					(mid 235.89996 -86.700106)
					(end 230.89997 -81.700116)
				)
			)
		)
	)
	(zone
		(layer "F.Cu")
		(hatch none 0.5)
		(connect_pads
			(clearance 0)
		)
		(min_thickness 0.25)
		(keepout
			(tracks not_allowed)
			(vias allowed)
			(pads allowed)
			(copperpour not_allowed)
			(footprints allowed)
		)
		(placement
			(enabled no)
			(sheetname "")
		)
		(fill
			(thermal_gap 0.5)
			(thermal_bridge_width 0.5)
			(island_removal_mode 0)
		)
		(polygon
			(pts
				(xy 135.755888 -345.461336) (xy 139.68984 -345.461336) (xy 139.68984 -345.408504) (xy 139.55776 -345.276424)
				(xy 138.143742 -345.276424) (xy 138.143742 -343.117424) (xy 140.300456 -343.117424) (xy 140.300456 -342.867742)
				(xy 137.96264 -342.867742) (xy 137.96264 -343.184988) (xy 137.852404 -343.184988) (xy 137.852404 -345.220798)
				(xy 135.998204 -345.220798) (xy 135.998204 -344.979752) (xy 135.755888 -344.979752)
			)
		)
	)
	(zone
		(layer "F.Cu")
		(hatch none 0.5)
		(connect_pads
			(clearance 0)
		)
		(min_thickness 0.25)
		(keepout
			(tracks not_allowed)
			(vias allowed)
			(pads allowed)
			(copperpour not_allowed)
			(footprints allowed)
		)
		(placement
			(enabled no)
			(sheetname "")
		)
		(fill
			(thermal_gap 0.5)
			(thermal_bridge_width 0.5)
			(island_removal_mode 0)
		)
		(polygon
			(pts
				(xy 54.98592 -146.891248) (xy 55.64886 -146.891248) (xy 55.64886 -145.341848) (xy 55.192168 -145.341848)
				(xy 55.192168 -146.037554) (xy 55.352696 -146.037554) (xy 55.352696 -146.596354) (xy 54.946296 -146.596354)
				(xy 54.946296 -146.037554) (xy 55.166768 -146.037554) (xy 55.166768 -145.341848) (xy 55.039768 -145.341848)
				(xy 55.039768 -145.797524) (xy 54.56682 -145.797524) (xy 54.56682 -146.03984) (xy 54.65318 -146.03984)
				(xy 54.65318 -146.639788) (xy 54.98592 -146.639788)
			)
		)
	)
	(zone
		(layer "F.Cu")
		(hatch none 0.5)
		(connect_pads
			(clearance 0)
		)
		(min_thickness 0.25)
		(keepout
			(tracks allowed)
			(vias allowed)
			(pads allowed)
			(copperpour allowed)
			(footprints allowed)
		)
		(placement
			(enabled no)
			(sheetname "")
		)
		(fill
			(thermal_gap 0.5)
			(thermal_bridge_width 0.5)
			(island_removal_mode 0)
		)
		(polygon
			(pts
				(xy 458.538326 -233.555032) (xy 458.538326 -233.326432) (xy 460.570326 -233.326432) (xy 460.570326 -233.555032)
			)
		)
	)
	(zone
		(layer "F.Cu")
		(hatch none 0.5)
		(connect_pads
			(clearance 0)
		)
		(min_thickness 0.25)
		(keepout
			(tracks allowed)
			(vias allowed)
			(pads allowed)
			(copperpour allowed)
			(footprints allowed)
		)
		(placement
			(enabled no)
			(sheetname "")
		)
		(fill
			(thermal_gap 0.5)
			(thermal_bridge_width 0.5)
			(island_removal_mode 0)
		)
		(polygon
			(pts
				(xy 151.79802 -53.157628) (xy 151.79802 -51.476148) (xy 153.56332 -51.476148) (xy 153.56332 -53.157628)
			)
		)
	)
	(zone
		(layer "F.Cu")
		(hatch none 0.5)
		(connect_pads
			(clearance 0)
		)
		(min_thickness 0.25)
		(keepout
			(tracks allowed)
			(vias allowed)
			(pads allowed)
			(copperpour allowed)
			(footprints allowed)
		)
		(placement
			(enabled no)
			(sheetname "")
		)
		(fill
			(thermal_gap 0.5)
			(thermal_bridge_width 0.5)
			(island_removal_mode 0)
		)
		(polygon
			(pts
				(xy 424.919394 -261.376414) (xy 426.951394 -261.376414) (xy 426.951394 -261.605014) (xy 424.919394 -261.605014)
				(xy 424.75277 -261.605014) (xy 424.75277 -261.376414)
			)
		)
	)
	(zone
		(layer "F.Cu")
		(hatch none 0.5)
		(connect_pads
			(clearance 0)
		)
		(min_thickness 0.25)
		(keepout
			(tracks allowed)
			(vias allowed)
			(pads allowed)
			(copperpour allowed)
			(footprints allowed)
		)
		(placement
			(enabled no)
			(sheetname "")
		)
		(fill
			(thermal_gap 0.5)
			(thermal_bridge_width 0.5)
			(island_removal_mode 0)
		)
		(polygon
			(pts
				(xy 44.735242 -271.916652) (xy 44.735242 -271.472914) (xy 47.060358 -271.472914) (xy 47.060358 -271.916652)
			)
		)
	)
	(zone
		(layer "F.Cu")
		(hatch none 0.5)
		(connect_pads
			(clearance 0)
		)
		(min_thickness 0.25)
		(keepout
			(tracks not_allowed)
			(vias allowed)
			(pads allowed)
			(copperpour not_allowed)
			(footprints allowed)
		)
		(placement
			(enabled no)
			(sheetname "")
		)
		(fill
			(thermal_gap 0.5)
			(thermal_bridge_width 0.5)
			(island_removal_mode 0)
		)
		(polygon
			(pts
				(arc
					(start 92.782898 -45.449998)
					(mid 91.182952 -47.049944)
					(end 92.782898 -48.64989)
				)
				(arc
					(start 94.383098 -48.64989)
					(mid 95.983044 -47.049944)
					(end 94.383098 -45.449998)
				)
			)
		)
	)
	(zone
		(layer "F.Cu")
		(hatch none 0.5)
		(connect_pads
			(clearance 0)
		)
		(min_thickness 0.25)
		(keepout
			(tracks allowed)
			(vias allowed)
			(pads allowed)
			(copperpour allowed)
			(footprints allowed)
		)
		(placement
			(enabled no)
			(sheetname "")
		)
		(fill
			(thermal_gap 0.5)
			(thermal_bridge_width 0.5)
			(island_removal_mode 0)
		)
		(polygon
			(pts
				(xy 405.731726 -293.05504) (xy 405.731726 -292.82644) (xy 407.763726 -292.82644) (xy 407.763726 -293.05504)
			)
		)
	)
	(zone
		(layer "F.Cu")
		(hatch none 0.5)
		(connect_pads
			(clearance 0)
		)
		(min_thickness 0.25)
		(keepout
			(tracks allowed)
			(vias allowed)
			(pads allowed)
			(copperpour allowed)
			(footprints allowed)
		)
		(placement
			(enabled no)
			(sheetname "")
		)
		(fill
			(thermal_gap 0.5)
			(thermal_bridge_width 0.5)
			(island_removal_mode 0)
		)
		(polygon
			(pts
				(xy 176.979326 -219.726256) (xy 179.011326 -219.726256) (xy 179.011326 -219.954856) (xy 176.979326 -219.954856)
				(xy 176.848008 -219.954856) (xy 176.8221 -219.954856) (xy 176.8221 -219.726256) (xy 176.848008 -219.726256)
			)
		)
	)
	(zone
		(layer "F.Cu")
		(hatch none 0.5)
		(connect_pads
			(clearance 0)
		)
		(min_thickness 0.25)
		(keepout
			(tracks allowed)
			(vias allowed)
			(pads allowed)
			(copperpour allowed)
			(footprints allowed)
		)
		(placement
			(enabled no)
			(sheetname "")
		)
		(fill
			(thermal_gap 0.5)
			(thermal_bridge_width 0.5)
			(island_removal_mode 0)
		)
		(polygon
			(pts
				(xy 274.143978 -286.366458) (xy 274.143978 -285.92272) (xy 276.469094 -285.92272) (xy 276.469094 -286.366458)
			)
		)
	)
	(zone
		(layer "F.Cu")
		(hatch none 0.5)
		(connect_pads
			(clearance 0)
		)
		(min_thickness 0.25)
		(keepout
			(tracks allowed)
			(vias allowed)
			(pads allowed)
			(copperpour allowed)
			(footprints allowed)
		)
		(placement
			(enabled no)
			(sheetname "")
		)
		(fill
			(thermal_gap 0.5)
			(thermal_bridge_width 0.5)
			(island_removal_mode 0)
		)
		(polygon
			(pts
				(xy 139.257278 -236.803946) (xy 139.460224 -236.601) (xy 139.460224 -236.55782) (xy 139.016486 -236.114082)
				(xy 138.894312 -236.114082) (xy 138.76147 -236.247178) (xy 138.76147 -236.351318) (xy 139.214098 -236.803946)
			)
		)
	)
	(zone
		(layer "F.Cu")
		(hatch none 0.5)
		(connect_pads
			(clearance 0)
		)
		(min_thickness 0.25)
		(keepout
			(tracks allowed)
			(vias allowed)
			(pads allowed)
			(copperpour allowed)
			(footprints allowed)
		)
		(placement
			(enabled no)
			(sheetname "")
		)
		(fill
			(thermal_gap 0.5)
			(thermal_bridge_width 0.5)
			(island_removal_mode 0)
		)
		(polygon
			(pts
				(xy 162.583368 -404.802594) (xy 162.583368 -399.959576) (xy 164.467794 -399.959576) (xy 164.467794 -404.802594)
			)
		)
	)
	(zone
		(layer "F.Cu")
		(hatch none 0.5)
		(connect_pads
			(clearance 0)
		)
		(min_thickness 0.25)
		(keepout
			(tracks allowed)
			(vias allowed)
			(pads allowed)
			(copperpour allowed)
			(footprints allowed)
		)
		(placement
			(enabled no)
			(sheetname "")
		)
		(fill
			(thermal_gap 0.5)
			(thermal_bridge_width 0.5)
			(island_removal_mode 0)
		)
		(polygon
			(pts
				(xy 307.76291 -222.616522) (xy 307.76291 -222.172784) (xy 310.088026 -222.172784) (xy 310.088026 -222.616522)
			)
		)
	)
	(zone
		(layer "F.Cu")
		(hatch none 0.5)
		(connect_pads
			(clearance 0)
		)
		(min_thickness 0.25)
		(keepout
			(tracks allowed)
			(vias allowed)
			(pads allowed)
			(copperpour allowed)
			(footprints allowed)
		)
		(placement
			(enabled no)
			(sheetname "")
		)
		(fill
			(thermal_gap 0.5)
			(thermal_bridge_width 0.5)
			(island_removal_mode 0)
		)
		(polygon
			(pts
				(xy 440.006994 -287.726374) (xy 442.038994 -287.726374) (xy 442.038994 -287.954974) (xy 440.006994 -287.954974)
				(xy 439.87085 -287.954974) (xy 439.82386 -287.954974) (xy 439.82386 -287.726374) (xy 439.87085 -287.726374)
			)
		)
	)
	(zone
		(layer "F.Cu")
		(hatch none 0.5)
		(connect_pads
			(clearance 0)
		)
		(min_thickness 0.25)
		(keepout
			(tracks allowed)
			(vias allowed)
			(pads allowed)
			(copperpour allowed)
			(footprints allowed)
		)
		(placement
			(enabled no)
			(sheetname "")
		)
		(fill
			(thermal_gap 0.5)
			(thermal_bridge_width 0.5)
			(island_removal_mode 0)
		)
		(polygon
			(pts
				(xy 59.822842 -296.56659) (xy 59.822842 -296.122852) (xy 62.147958 -296.122852) (xy 62.147958 -296.56659)
			)
		)
	)
	(zone
		(layer "F.Cu")
		(hatch none 0.5)
		(connect_pads
			(clearance 0)
		)
		(min_thickness 0.25)
		(keepout
			(tracks allowed)
			(vias allowed)
			(pads allowed)
			(copperpour allowed)
			(footprints allowed)
		)
		(placement
			(enabled no)
			(sheetname "")
		)
		(fill
			(thermal_gap 0.5)
			(thermal_bridge_width 0.5)
			(island_removal_mode 0)
		)
		(polygon
			(pts
				(xy 195.510658 -196.154802) (xy 195.510658 -195.926202) (xy 197.542658 -195.926202) (xy 197.542658 -196.154802)
			)
		)
	)
	(zone
		(layer "F.Cu")
		(hatch none 0.5)
		(connect_pads
			(clearance 0)
		)
		(min_thickness 0.25)
		(keepout
			(tracks allowed)
			(vias allowed)
			(pads allowed)
			(copperpour allowed)
			(footprints allowed)
		)
		(placement
			(enabled no)
			(sheetname "")
		)
		(fill
			(thermal_gap 0.5)
			(thermal_bridge_width 0.5)
			(island_removal_mode 0)
		)
		(polygon
			(pts
				(xy 274.143978 -233.2228) (xy 276.469094 -233.2228) (xy 276.530562 -233.2228) (xy 276.530562 -234.14609)
				(xy 274.005802 -234.14609) (xy 274.005802 -233.2228)
			)
		)
	)
	(zone
		(layer "F.Cu")
		(hatch none 0.5)
		(connect_pads
			(clearance 0)
		)
		(min_thickness 0.25)
		(keepout
			(tracks allowed)
			(vias allowed)
			(pads allowed)
			(copperpour allowed)
			(footprints allowed)
		)
		(placement
			(enabled no)
			(sheetname "")
		)
		(fill
			(thermal_gap 0.5)
			(thermal_bridge_width 0.5)
			(island_removal_mode 0)
		)
		(polygon
			(pts
				(xy 157.791658 -261.605014) (xy 157.791658 -261.376414) (xy 159.823658 -261.376414) (xy 159.823658 -261.605014)
			)
		)
	)
	(zone
		(layer "F.Cu")
		(hatch none 0.5)
		(connect_pads
			(clearance 0)
		)
		(min_thickness 0.25)
		(keepout
			(tracks allowed)
			(vias allowed)
			(pads allowed)
			(copperpour allowed)
			(footprints allowed)
		)
		(placement
			(enabled no)
			(sheetname "")
		)
		(fill
			(thermal_gap 0.5)
			(thermal_bridge_width 0.5)
			(island_removal_mode 0)
		)
		(polygon
			(pts
				(xy 384.44424 -285.745428) (xy 384.73126 -285.745428) (xy 384.76174 -285.714948) (xy 384.76174 -285.087568)
				(xy 384.67538 -285.001208) (xy 384.48742 -285.001208) (xy 384.41376 -285.074868) (xy 384.41376 -285.714948)
			)
		)
	)
	(zone
		(layer "F.Cu")
		(hatch none 0.5)
		(connect_pads
			(clearance 0)
		)
		(min_thickness 0.25)
		(keepout
			(tracks allowed)
			(vias allowed)
			(pads allowed)
			(copperpour allowed)
			(footprints allowed)
		)
		(placement
			(enabled no)
			(sheetname "")
		)
		(fill
			(thermal_gap 0.5)
			(thermal_bridge_width 0.5)
			(island_removal_mode 0)
		)
		(polygon
			(pts
				(xy 274.143978 -207.316578) (xy 274.143978 -206.87284) (xy 276.469094 -206.87284) (xy 276.469094 -207.316578)
			)
		)
	)
	(zone
		(layer "F.Cu")
		(hatch none 0.5)
		(connect_pads
			(clearance 0)
		)
		(min_thickness 0.25)
		(keepout
			(tracks allowed)
			(vias allowed)
			(pads allowed)
			(copperpour allowed)
			(footprints allowed)
		)
		(placement
			(enabled no)
			(sheetname "")
		)
		(fill
			(thermal_gap 0.5)
			(thermal_bridge_width 0.5)
			(island_removal_mode 0)
		)
		(polygon
			(pts
				(xy 289.231578 -305.066446) (xy 289.231578 -304.622708) (xy 291.556694 -304.622708) (xy 291.556694 -305.066446)
			)
		)
	)
	(zone
		(layer "F.Cu")
		(hatch none 0.5)
		(connect_pads
			(clearance 0)
		)
		(min_thickness 0.25)
		(keepout
			(tracks allowed)
			(vias allowed)
			(pads allowed)
			(copperpour allowed)
			(footprints allowed)
		)
		(placement
			(enabled no)
			(sheetname "")
		)
		(fill
			(thermal_gap 0.5)
			(thermal_bridge_width 0.5)
			(island_removal_mode 0)
		)
		(polygon
			(pts
				(xy 56.37911 -214.96655) (xy 56.37911 -214.522812) (xy 58.704226 -214.522812) (xy 58.704226 -214.96655)
			)
		)
	)
	(zone
		(layer "F.Cu")
		(hatch none 0.5)
		(connect_pads
			(clearance 0)
		)
		(min_thickness 0.25)
		(keepout
			(tracks allowed)
			(vias allowed)
			(pads allowed)
			(copperpour allowed)
			(footprints allowed)
		)
		(placement
			(enabled no)
			(sheetname "")
		)
		(fill
			(thermal_gap 0.5)
			(thermal_bridge_width 0.5)
			(island_removal_mode 0)
		)
		(polygon
			(pts
				(xy 207.154526 -238.426244) (xy 209.186526 -238.426244) (xy 209.186526 -238.654844) (xy 207.154526 -238.654844)
				(xy 207.023208 -238.654844) (xy 206.9973 -238.654844) (xy 206.9973 -238.426244) (xy 207.023208 -238.426244)
			)
		)
	)
	(zone
		(layer "F.Cu")
		(hatch none 0.5)
		(connect_pads
			(clearance 0)
		)
		(min_thickness 0.25)
		(keepout
			(tracks allowed)
			(vias allowed)
			(pads allowed)
			(copperpour allowed)
			(footprints allowed)
		)
		(placement
			(enabled no)
			(sheetname "")
		)
		(fill
			(thermal_gap 0.5)
			(thermal_bridge_width 0.5)
			(island_removal_mode 0)
		)
		(polygon
			(pts
				(xy 292.67531 -225.166428) (xy 292.67531 -224.72269) (xy 295.000426 -224.72269) (xy 295.000426 -225.166428)
			)
		)
	)
	(zone
		(layer "F.Cu")
		(hatch none 0.5)
		(connect_pads
			(clearance 0)
		)
		(min_thickness 0.25)
		(keepout
			(tracks allowed)
			(vias allowed)
			(pads allowed)
			(copperpour allowed)
			(footprints allowed)
		)
		(placement
			(enabled no)
			(sheetname "")
		)
		(fill
			(thermal_gap 0.5)
			(thermal_bridge_width 0.5)
			(island_removal_mode 0)
		)
		(polygon
			(pts
				(xy 41.29151 -286.366458) (xy 41.29151 -285.92272) (xy 43.616626 -285.92272) (xy 43.616626 -286.366458)
			)
		)
	)
	(zone
		(layer "F.Cu")
		(hatch none 0.5)
		(connect_pads
			(clearance 0)
		)
		(min_thickness 0.25)
		(keepout
			(tracks allowed)
			(vias allowed)
			(pads allowed)
			(copperpour allowed)
			(footprints allowed)
		)
		(placement
			(enabled no)
			(sheetname "")
		)
		(fill
			(thermal_gap 0.5)
			(thermal_bridge_width 0.5)
			(island_removal_mode 0)
		)
		(polygon
			(pts
				(xy 165.335458 -282.854908) (xy 165.335458 -282.626308) (xy 167.367458 -282.626308) (xy 167.367458 -282.854908)
			)
		)
	)
	(zone
		(layer "F.Cu")
		(hatch none 0.5)
		(connect_pads
			(clearance 0)
		)
		(min_thickness 0.25)
		(keepout
			(tracks allowed)
			(vias allowed)
			(pads allowed)
			(copperpour allowed)
			(footprints allowed)
		)
		(placement
			(enabled no)
			(sheetname "")
		)
		(fill
			(thermal_gap 0.5)
			(thermal_bridge_width 0.5)
			(island_removal_mode 0)
		)
		(polygon
			(pts
				(xy 458.538326 -202.105006) (xy 458.538326 -201.876406) (xy 460.570326 -201.876406) (xy 460.570326 -202.105006)
			)
		)
	)
	(zone
		(layer "F.Cu")
		(hatch none 0.5)
		(connect_pads
			(clearance 0)
		)
		(min_thickness 0.25)
		(keepout
			(tracks allowed)
			(vias allowed)
			(pads allowed)
			(copperpour allowed)
			(footprints allowed)
		)
		(placement
			(enabled no)
			(sheetname "")
		)
		(fill
			(thermal_gap 0.5)
			(thermal_bridge_width 0.5)
			(island_removal_mode 0)
		)
		(polygon
			(pts
				(xy 428.363126 -250.554998) (xy 428.363126 -250.326398) (xy 430.395126 -250.326398) (xy 430.395126 -250.554998)
			)
		)
	)
	(zone
		(layer "F.Cu")
		(hatch none 0.5)
		(connect_pads
			(clearance 0)
		)
		(min_thickness 0.25)
		(keepout
			(tracks allowed)
			(vias allowed)
			(pads allowed)
			(copperpour allowed)
			(footprints allowed)
		)
		(placement
			(enabled no)
			(sheetname "")
		)
		(fill
			(thermal_gap 0.5)
			(thermal_bridge_width 0.5)
			(island_removal_mode 0)
		)
		(polygon
			(pts
				(xy 138.2141 -20.61718) (xy 138.2141 -19.26336) (xy 140.9954 -19.26336) (xy 140.9954 -20.61718)
			)
		)
	)
	(zone
		(layer "F.Cu")
		(hatch none 0.5)
		(connect_pads
			(clearance 0)
		)
		(min_thickness 0.25)
		(keepout
			(tracks allowed)
			(vias allowed)
			(pads allowed)
			(copperpour allowed)
			(footprints allowed)
		)
		(placement
			(enabled no)
			(sheetname "")
		)
		(fill
			(thermal_gap 0.5)
			(thermal_bridge_width 0.5)
			(island_removal_mode 0)
		)
		(polygon
			(pts
				(xy 415.307526 -236.954822) (xy 413.275526 -236.954822) (xy 412.85033 -236.954822) (xy 412.85033 -235.891324)
				(xy 415.705544 -235.891324) (xy 415.705544 -236.954822)
			)
		)
	)
	(zone
		(layer "F.Cu")
		(hatch none 0.5)
		(connect_pads
			(clearance 0)
		)
		(min_thickness 0.25)
		(keepout
			(tracks allowed)
			(vias allowed)
			(pads allowed)
			(copperpour allowed)
			(footprints allowed)
		)
		(placement
			(enabled no)
			(sheetname "")
		)
		(fill
			(thermal_gap 0.5)
			(thermal_bridge_width 0.5)
			(island_removal_mode 0)
		)
		(polygon
			(pts
				(xy 292.67531 -236.216444) (xy 292.67531 -235.772706) (xy 295.000426 -235.772706) (xy 295.000426 -236.216444)
			)
		)
	)
	(zone
		(layer "F.Cu")
		(hatch none 0.5)
		(connect_pads
			(clearance 0)
		)
		(min_thickness 0.25)
		(keepout
			(tracks not_allowed)
			(vias allowed)
			(pads allowed)
			(copperpour not_allowed)
			(footprints allowed)
		)
		(placement
			(enabled no)
			(sheetname "")
		)
		(fill
			(thermal_gap 0.5)
			(thermal_bridge_width 0.5)
			(island_removal_mode 0)
		)
		(polygon
			(pts
				(arc
					(start 283.979874 -419.999922)
					(mid 287.98012 -415.999676)
					(end 291.980112 -419.999922)
				)
				(arc
					(start 291.980112 -419.999922)
					(mid 287.98012 -423.999914)
					(end 283.979874 -419.999922)
				)
			)
		)
	)
	(zone
		(layer "F.Cu")
		(hatch none 0.5)
		(connect_pads
			(clearance 0)
		)
		(min_thickness 0.25)
		(keepout
			(tracks allowed)
			(vias allowed)
			(pads allowed)
			(copperpour allowed)
			(footprints allowed)
		)
		(placement
			(enabled no)
			(sheetname "")
		)
		(fill
			(thermal_gap 0.5)
			(thermal_bridge_width 0.5)
			(island_removal_mode 0)
		)
		(polygon
			(pts
				(xy 395.471904 -404.802594) (xy 395.471904 -399.959576) (xy 397.35633 -399.959576) (xy 397.35633 -404.802594)
			)
		)
	)
	(zone
		(layer "F.Cu")
		(hatch none 0.5)
		(connect_pads
			(clearance 0)
		)
		(min_thickness 0.25)
		(keepout
			(tracks allowed)
			(vias allowed)
			(pads allowed)
			(copperpour allowed)
			(footprints allowed)
		)
		(placement
			(enabled no)
			(sheetname "")
		)
		(fill
			(thermal_gap 0.5)
			(thermal_bridge_width 0.5)
			(island_removal_mode 0)
		)
		(polygon
			(pts
				(xy 41.29151 -211.566506) (xy 41.29151 -211.122768) (xy 43.616626 -211.122768) (xy 43.616626 -211.566506)
			)
		)
	)
	(zone
		(layer "F.Cu")
		(hatch none 0.5)
		(connect_pads
			(clearance 0)
		)
		(min_thickness 0.25)
		(keepout
			(tracks allowed)
			(vias allowed)
			(pads allowed)
			(copperpour allowed)
			(footprints allowed)
		)
		(placement
			(enabled no)
			(sheetname "")
		)
		(fill
			(thermal_gap 0.5)
			(thermal_bridge_width 0.5)
			(island_removal_mode 0)
		)
		(polygon
			(pts
				(xy 143.88338 -345.478608) (xy 143.88338 -343.383108) (xy 145.39976 -343.383108) (xy 145.39976 -345.478608)
			)
		)
	)
	(zone
		(layer "F.Cu")
		(hatch none 0.5)
		(connect_pads
			(clearance 0)
		)
		(min_thickness 0.25)
		(keepout
			(tracks allowed)
			(vias allowed)
			(pads allowed)
			(copperpour allowed)
			(footprints not_allowed)
		)
		(placement
			(enabled no)
			(sheetname "")
		)
		(fill
			(thermal_gap 0.5)
			(thermal_bridge_width 0.5)
			(island_removal_mode 0)
		)
		(polygon
			(pts
				(xy 0.083312 -14.780006) (xy 0.083312 -6.780022) (xy 11.08329 -6.780022) (xy 11.08329 -14.780006)
			)
		)
	)
	(zone
		(layer "F.Cu")
		(hatch none 0.5)
		(connect_pads
			(clearance 0)
		)
		(min_thickness 0.25)
		(keepout
			(tracks allowed)
			(vias allowed)
			(pads allowed)
			(copperpour allowed)
			(footprints allowed)
		)
		(placement
			(enabled no)
			(sheetname "")
		)
		(fill
			(thermal_gap 0.5)
			(thermal_bridge_width 0.5)
			(island_removal_mode 0)
		)
		(polygon
			(pts
				(xy 176.979326 -237.806992) (xy 179.011326 -237.806992) (xy 179.011326 -237.578392) (xy 176.979326 -237.578392)
				(xy 176.848008 -237.578392) (xy 176.8221 -237.578392) (xy 176.8221 -237.806992) (xy 176.848008 -237.806992)
			)
		)
	)
	(zone
		(layer "F.Cu")
		(hatch none 0.5)
		(connect_pads
			(clearance 0)
		)
		(min_thickness 0.25)
		(keepout
			(tracks allowed)
			(vias allowed)
			(pads allowed)
			(copperpour allowed)
			(footprints allowed)
		)
		(placement
			(enabled no)
			(sheetname "")
		)
		(fill
			(thermal_gap 0.5)
			(thermal_bridge_width 0.5)
			(island_removal_mode 0)
		)
		(polygon
			(pts
				(xy 458.538326 -241.205004) (xy 458.538326 -240.976404) (xy 460.570326 -240.976404) (xy 460.570326 -241.205004)
			)
		)
	)
	(zone
		(layer "F.Cu")
		(hatch none 0.5)
		(connect_pads
			(clearance 0)
		)
		(min_thickness 0.25)
		(keepout
			(tracks allowed)
			(vias allowed)
			(pads allowed)
			(copperpour allowed)
			(footprints allowed)
		)
		(placement
			(enabled no)
			(sheetname "")
		)
		(fill
			(thermal_gap 0.5)
			(thermal_bridge_width 0.5)
			(island_removal_mode 0)
		)
		(polygon
			(pts
				(xy 197.553834 -278.607012) (xy 195.521834 -278.607012) (xy 195.521834 -278.604726) (xy 195.343018 -278.604726)
				(xy 195.343018 -278.36749) (xy 195.205096 -278.36749) (xy 195.161916 -278.32431) (xy 195.161916 -278.191468)
				(xy 195.161916 -277.88743) (xy 195.23456 -277.814786) (xy 197.774814 -277.814786) (xy 197.916038 -277.95601)
				(xy 197.916038 -278.153114) (xy 197.834504 -278.234648) (xy 197.834504 -278.607012) (xy 197.736968 -278.607012)
				(xy 197.689978 -278.607012)
			)
		)
	)
	(zone
		(layer "F.Cu")
		(hatch none 0.5)
		(connect_pads
			(clearance 0)
		)
		(min_thickness 0.25)
		(keepout
			(tracks allowed)
			(vias allowed)
			(pads allowed)
			(copperpour allowed)
			(footprints not_allowed)
		)
		(placement
			(enabled no)
			(sheetname "")
		)
		(fill
			(thermal_gap 0.5)
			(thermal_bridge_width 0.5)
			(island_removal_mode 0)
		)
		(polygon
			(pts
				(arc
					(start 372.89994 -22.29993)
					(mid 380.899924 -14.299946)
					(end 388.899908 -22.29993)
				)
				(arc
					(start 388.899908 -22.29993)
					(mid 380.899924 -30.299914)
					(end 372.89994 -22.29993)
				)
			)
		)
	)
	(zone
		(layer "F.Cu")
		(hatch none 0.5)
		(connect_pads
			(clearance 0)
		)
		(min_thickness 0.25)
		(keepout
			(tracks allowed)
			(vias allowed)
			(pads allowed)
			(copperpour allowed)
			(footprints allowed)
		)
		(placement
			(enabled no)
			(sheetname "")
		)
		(fill
			(thermal_gap 0.5)
			(thermal_bridge_width 0.5)
			(island_removal_mode 0)
		)
		(polygon
			(pts
				(xy 56.37911 -209.866484) (xy 56.37911 -209.422746) (xy 58.704226 -209.422746) (xy 58.704226 -209.866484)
			)
		)
	)
	(zone
		(layer "F.Cu")
		(hatch none 0.5)
		(connect_pads
			(clearance 0)
		)
		(min_thickness 0.25)
		(keepout
			(tracks allowed)
			(vias allowed)
			(pads allowed)
			(copperpour allowed)
			(footprints allowed)
		)
		(placement
			(enabled no)
			(sheetname "")
		)
		(fill
			(thermal_gap 0.5)
			(thermal_bridge_width 0.5)
			(island_removal_mode 0)
		)
		(polygon
			(pts
				(xy 428.363126 -207.204818) (xy 428.363126 -206.976218) (xy 430.395126 -206.976218) (xy 430.395126 -207.204818)
			)
		)
	)
	(zone
		(layer "F.Cu")
		(hatch none 0.5)
		(connect_pads
			(clearance 0)
		)
		(min_thickness 0.25)
		(keepout
			(tracks allowed)
			(vias allowed)
			(pads allowed)
			(copperpour allowed)
			(footprints not_allowed)
		)
		(placement
			(enabled no)
			(sheetname "")
		)
		(fill
			(thermal_gap 0.5)
			(thermal_bridge_width 0.5)
			(island_removal_mode 0)
		)
		(polygon
			(pts
				(xy 59.947302 -330.091796) (xy 66.047112 -330.091796) (xy 66.047112 -186.09183) (xy 59.947302 -186.09183)
			)
		)
	)
	(zone
		(layer "F.Cu")
		(hatch none 0.5)
		(connect_pads
			(clearance 0)
		)
		(min_thickness 0.25)
		(keepout
			(tracks allowed)
			(vias allowed)
			(pads allowed)
			(copperpour allowed)
			(footprints allowed)
		)
		(placement
			(enabled no)
			(sheetname "")
		)
		(fill
			(thermal_gap 0.5)
			(thermal_bridge_width 0.5)
			(island_removal_mode 0)
		)
		(polygon
			(pts
				(xy 307.76291 -305.066446) (xy 307.76291 -304.622708) (xy 310.088026 -304.622708) (xy 310.088026 -305.066446)
			)
		)
	)
	(zone
		(layer "F.Cu")
		(hatch none 0.5)
		(connect_pads
			(clearance 0)
		)
		(min_thickness 0.25)
		(keepout
			(tracks allowed)
			(vias allowed)
			(pads allowed)
			(copperpour allowed)
			(footprints allowed)
		)
		(placement
			(enabled no)
			(sheetname "")
		)
		(fill
			(thermal_gap 0.5)
			(thermal_bridge_width 0.5)
			(island_removal_mode 0)
		)
		(polygon
			(pts
				(xy 326.312022 -410.948886) (xy 326.312022 -406.105868) (xy 328.196448 -406.105868) (xy 328.196448 -410.948886)
			)
		)
	)
	(zone
		(layer "F.Cu")
		(hatch none 0.5)
		(connect_pads
			(clearance 0)
		)
		(min_thickness 0.25)
		(keepout
			(tracks allowed)
			(vias allowed)
			(pads allowed)
			(copperpour allowed)
			(footprints allowed)
		)
		(placement
			(enabled no)
			(sheetname "")
		)
		(fill
			(thermal_gap 0.5)
			(thermal_bridge_width 0.5)
			(island_removal_mode 0)
		)
		(polygon
			(pts
				(xy 84.96046 -342.395048) (xy 84.96046 -339.669628) (xy 90.76182 -339.669628) (xy 90.76182 -342.395048)
			)
		)
	)
	(zone
		(layer "F.Cu")
		(hatch none 0.5)
		(connect_pads
			(clearance 0)
		)
		(min_thickness 0.25)
		(keepout
			(tracks allowed)
			(vias allowed)
			(pads allowed)
			(copperpour allowed)
			(footprints allowed)
		)
		(placement
			(enabled no)
			(sheetname "")
		)
		(fill
			(thermal_gap 0.5)
			(thermal_bridge_width 0.5)
			(island_removal_mode 0)
		)
		(polygon
			(pts
				(xy 16.48968 -9.139428) (xy 16.48968 -6.937248) (xy 17.7673 -6.937248) (xy 17.7673 -9.139428)
			)
		)
	)
	(zone
		(layer "F.Cu")
		(hatch none 0.5)
		(connect_pads
			(clearance 0)
		)
		(min_thickness 0.25)
		(keepout
			(tracks allowed)
			(vias allowed)
			(pads allowed)
			(copperpour allowed)
			(footprints allowed)
		)
		(placement
			(enabled no)
			(sheetname "")
		)
		(fill
			(thermal_gap 0.5)
			(thermal_bridge_width 0.5)
			(island_removal_mode 0)
		)
		(polygon
			(pts
				(xy 14.560042 -225.166428) (xy 14.560042 -224.72269) (xy 16.885158 -224.72269) (xy 16.885158 -225.166428)
			)
		)
	)
	(zone
		(layer "F.Cu")
		(hatch none 0.5)
		(connect_pads
			(clearance 0)
		)
		(min_thickness 0.25)
		(keepout
			(tracks allowed)
			(vias allowed)
			(pads allowed)
			(copperpour allowed)
			(footprints allowed)
		)
		(placement
			(enabled no)
			(sheetname "")
		)
		(fill
			(thermal_gap 0.5)
			(thermal_bridge_width 0.5)
			(island_removal_mode 0)
		)
		(polygon
			(pts
				(xy 424.919394 -287.726374) (xy 426.951394 -287.726374) (xy 426.951394 -287.954974) (xy 424.919394 -287.954974)
				(xy 424.78325 -287.954974) (xy 424.73626 -287.954974) (xy 424.73626 -287.726374) (xy 424.78325 -287.726374)
			)
		)
	)
	(zone
		(layer "F.Cu")
		(hatch none 0.5)
		(connect_pads
			(clearance 0)
		)
		(min_thickness 0.25)
		(keepout
			(tracks allowed)
			(vias allowed)
			(pads allowed)
			(copperpour allowed)
			(footprints allowed)
		)
		(placement
			(enabled no)
			(sheetname "")
		)
		(fill
			(thermal_gap 0.5)
			(thermal_bridge_width 0.5)
			(island_removal_mode 0)
		)
		(polygon
			(pts
				(xy 79.501492 -410.948886) (xy 79.501492 -406.105868) (xy 81.385918 -406.105868) (xy 81.385918 -410.948886)
			)
		)
	)
	(zone
		(layer "F.Cu")
		(hatch none 0.5)
		(connect_pads
			(clearance 0)
		)
		(min_thickness 0.25)
		(keepout
			(tracks allowed)
			(vias allowed)
			(pads allowed)
			(copperpour allowed)
			(footprints allowed)
		)
		(placement
			(enabled no)
			(sheetname "")
		)
		(fill
			(thermal_gap 0.5)
			(thermal_bridge_width 0.5)
			(island_removal_mode 0)
		)
		(polygon
			(pts
				(xy 413.275526 -224.204784) (xy 413.275526 -223.976184) (xy 415.307526 -223.976184) (xy 415.307526 -224.204784)
			)
		)
	)
	(zone
		(layer "F.Cu")
		(hatch none 0.5)
		(connect_pads
			(clearance 0)
		)
		(min_thickness 0.25)
		(keepout
			(tracks allowed)
			(vias allowed)
			(pads allowed)
			(copperpour allowed)
			(footprints allowed)
		)
		(placement
			(enabled no)
			(sheetname "")
		)
		(fill
			(thermal_gap 0.5)
			(thermal_bridge_width 0.5)
			(island_removal_mode 0)
		)
		(polygon
			(pts
				(xy 405.731726 -246.304816) (xy 405.731726 -246.076216) (xy 407.763726 -246.076216) (xy 407.763726 -246.304816)
			)
		)
	)
	(zone
		(layer "F.Cu")
		(hatch none 0.5)
		(connect_pads
			(clearance 0)
		)
		(min_thickness 0.25)
		(keepout
			(tracks allowed)
			(vias allowed)
			(pads allowed)
			(copperpour allowed)
			(footprints allowed)
		)
		(placement
			(enabled no)
			(sheetname "")
		)
		(fill
			(thermal_gap 0.5)
			(thermal_bridge_width 0.5)
			(island_removal_mode 0)
		)
		(polygon
			(pts
				(xy 41.29151 -289.766502) (xy 41.29151 -289.322764) (xy 43.616626 -289.322764) (xy 43.616626 -289.766502)
			)
		)
	)
	(zone
		(layer "F.Cu")
		(hatch none 0.5)
		(connect_pads
			(clearance 0)
		)
		(min_thickness 0.25)
		(keepout
			(tracks allowed)
			(vias allowed)
			(pads allowed)
			(copperpour allowed)
			(footprints allowed)
		)
		(placement
			(enabled no)
			(sheetname "")
		)
		(fill
			(thermal_gap 0.5)
			(thermal_bridge_width 0.5)
			(island_removal_mode 0)
		)
		(polygon
			(pts
				(xy 447.29273 -319.243202) (xy 447.29273 -316.881002) (xy 449.90893 -316.881002) (xy 449.90893 -319.243202)
			)
		)
	)
	(zone
		(layer "F.Cu")
		(hatch none 0.5)
		(connect_pads
			(clearance 0)
		)
		(min_thickness 0.25)
		(keepout
			(tracks allowed)
			(vias allowed)
			(pads allowed)
			(copperpour allowed)
			(footprints allowed)
		)
		(placement
			(enabled no)
			(sheetname "")
		)
		(fill
			(thermal_gap 0.5)
			(thermal_bridge_width 0.5)
			(island_removal_mode 0)
		)
		(polygon
			(pts
				(xy 298.466002 -365.01832) (xy 296.718482 -365.01832) (xy 296.718482 -363.08284) (xy 298.466002 -363.08284)
			)
		)
	)
	(zone
		(layer "F.Cu")
		(hatch none 0.5)
		(connect_pads
			(clearance 0)
		)
		(min_thickness 0.25)
		(keepout
			(tracks allowed)
			(vias allowed)
			(pads allowed)
			(copperpour allowed)
			(footprints allowed)
		)
		(placement
			(enabled no)
			(sheetname "")
		)
		(fill
			(thermal_gap 0.5)
			(thermal_bridge_width 0.5)
			(island_removal_mode 0)
		)
		(polygon
			(pts
				(xy 65.32118 -29.187648) (xy 65.32118 -30.104588) (xy 65.75298 -30.536388) (xy 66.02984 -30.536388)
				(xy 66.42608 -30.140148) (xy 66.42608 -29.164788) (xy 66.11366 -28.852368) (xy 65.65646 -28.852368)
			)
		)
	)
	(zone
		(layer "F.Cu")
		(hatch none 0.5)
		(connect_pads
			(clearance 0)
		)
		(min_thickness 0.25)
		(keepout
			(tracks allowed)
			(vias allowed)
			(pads allowed)
			(copperpour allowed)
			(footprints allowed)
		)
		(placement
			(enabled no)
			(sheetname "")
		)
		(fill
			(thermal_gap 0.5)
			(thermal_bridge_width 0.5)
			(island_removal_mode 0)
		)
		(polygon
			(pts
				(xy 458.538326 -247.154954) (xy 458.538326 -246.926354) (xy 460.570326 -246.926354) (xy 460.570326 -247.154954)
			)
		)
	)
	(zone
		(layer "F.Cu")
		(hatch none 0.5)
		(connect_pads
			(clearance 0)
		)
		(min_thickness 0.25)
		(keepout
			(tracks allowed)
			(vias allowed)
			(pads allowed)
			(copperpour allowed)
			(footprints allowed)
		)
		(placement
			(enabled no)
			(sheetname "")
		)
		(fill
			(thermal_gap 0.5)
			(thermal_bridge_width 0.5)
			(island_removal_mode 0)
		)
		(polygon
			(pts
				(xy 53.649372 -404.802594) (xy 53.649372 -399.959576) (xy 55.533798 -399.959576) (xy 55.533798 -404.802594)
			)
		)
	)
	(zone
		(layer "F.Cu")
		(hatch none 0.5)
		(connect_pads
			(clearance 0)
		)
		(min_thickness 0.25)
		(keepout
			(tracks allowed)
			(vias allowed)
			(pads allowed)
			(copperpour allowed)
			(footprints allowed)
		)
		(placement
			(enabled no)
			(sheetname "")
		)
		(fill
			(thermal_gap 0.5)
			(thermal_bridge_width 0.5)
			(island_removal_mode 0)
		)
		(polygon
			(pts
				(xy 192.066926 -225.67646) (xy 194.098926 -225.67646) (xy 194.098926 -225.90506) (xy 192.066926 -225.90506)
				(xy 191.930782 -225.90506) (xy 191.883792 -225.90506) (xy 191.883792 -225.67646) (xy 191.930782 -225.67646)
			)
		)
	)
	(zone
		(layer "F.Cu")
		(hatch none 0.5)
		(connect_pads
			(clearance 0)
		)
		(min_thickness 0.25)
		(keepout
			(tracks allowed)
			(vias allowed)
			(pads allowed)
			(copperpour allowed)
			(footprints allowed)
		)
		(placement
			(enabled no)
			(sheetname "")
		)
		(fill
			(thermal_gap 0.5)
			(thermal_bridge_width 0.5)
			(island_removal_mode 0)
		)
		(polygon
			(pts
				(xy 409.831794 -286.254952) (xy 409.831794 -286.026352) (xy 411.863794 -286.026352) (xy 411.863794 -286.254952)
			)
		)
	)
	(zone
		(layer "F.Cu")
		(hatch none 0.5)
		(connect_pads
			(clearance 0)
		)
		(min_thickness 0.25)
		(keepout
			(tracks allowed)
			(vias allowed)
			(pads allowed)
			(copperpour allowed)
			(footprints allowed)
		)
		(placement
			(enabled no)
			(sheetname "")
		)
		(fill
			(thermal_gap 0.5)
			(thermal_bridge_width 0.5)
			(island_removal_mode 0)
		)
		(polygon
			(pts
				(xy 56.37911 -314.41644) (xy 56.37911 -313.972702) (xy 58.704226 -313.972702) (xy 58.704226 -314.41644)
			)
		)
	)
	(zone
		(layer "F.Cu")
		(hatch none 0.5)
		(connect_pads
			(clearance 0)
		)
		(min_thickness 0.25)
		(keepout
			(tracks allowed)
			(vias allowed)
			(pads allowed)
			(copperpour allowed)
			(footprints allowed)
		)
		(placement
			(enabled no)
			(sheetname "")
		)
		(fill
			(thermal_gap 0.5)
			(thermal_bridge_width 0.5)
			(island_removal_mode 0)
		)
		(polygon
			(pts
				(xy 440.006994 -298.77639) (xy 442.038994 -298.77639) (xy 442.038994 -299.00499) (xy 440.006994 -299.00499)
				(xy 439.87085 -299.00499) (xy 439.82386 -299.00499) (xy 439.82386 -298.77639) (xy 439.87085 -298.77639)
			)
		)
	)
	(zone
		(layer "F.Cu")
		(hatch none 0.5)
		(connect_pads
			(clearance 0)
		)
		(min_thickness 0.25)
		(keepout
			(tracks allowed)
			(vias allowed)
			(pads allowed)
			(copperpour allowed)
			(footprints allowed)
		)
		(placement
			(enabled no)
			(sheetname "")
		)
		(fill
			(thermal_gap 0.5)
			(thermal_bridge_width 0.5)
			(island_removal_mode 0)
		)
		(polygon
			(pts
				(xy 165.646608 -404.802594) (xy 165.646608 -399.959576) (xy 167.531034 -399.959576) (xy 167.531034 -404.802594)
			)
		)
	)
	(zone
		(layer "F.Cu")
		(hatch none 0.5)
		(connect_pads
			(clearance 0)
		)
		(min_thickness 0.25)
		(keepout
			(tracks allowed)
			(vias allowed)
			(pads allowed)
			(copperpour allowed)
			(footprints allowed)
		)
		(placement
			(enabled no)
			(sheetname "")
		)
		(fill
			(thermal_gap 0.5)
			(thermal_bridge_width 0.5)
			(island_removal_mode 0)
		)
		(polygon
			(pts
				(xy 180.423058 -304.95494) (xy 180.423058 -304.72634) (xy 182.455058 -304.72634) (xy 182.455058 -304.95494)
			)
		)
	)
	(zone
		(layer "F.Cu")
		(hatch none 0.5)
		(connect_pads
			(clearance 0)
		)
		(min_thickness 0.25)
		(keepout
			(tracks allowed)
			(vias allowed)
			(pads allowed)
			(copperpour allowed)
			(footprints allowed)
		)
		(placement
			(enabled no)
			(sheetname "")
		)
		(fill
			(thermal_gap 0.5)
			(thermal_bridge_width 0.5)
			(island_removal_mode 0)
		)
		(polygon
			(pts
				(xy 63.900812 -294.866568) (xy 63.900812 -294.42283) (xy 66.237612 -294.42283) (xy 66.237612 -294.866568)
			)
		)
	)
	(zone
		(layer "F.Cu")
		(hatch none 0.5)
		(connect_pads
			(clearance 0)
		)
		(min_thickness 0.25)
		(keepout
			(tracks allowed)
			(vias allowed)
			(pads allowed)
			(copperpour allowed)
			(footprints allowed)
		)
		(placement
			(enabled no)
			(sheetname "")
		)
		(fill
			(thermal_gap 0.5)
			(thermal_bridge_width 0.5)
			(island_removal_mode 0)
		)
		(polygon
			(pts
				(xy 304.168556 -319.243456) (xy 304.168556 -316.881256) (xy 306.784756 -316.881256) (xy 306.784756 -319.243456)
			)
		)
	)
	(zone
		(layer "F.Cu")
		(hatch none 0.5)
		(connect_pads
			(clearance 0)
		)
		(min_thickness 0.25)
		(keepout
			(tracks allowed)
			(vias allowed)
			(pads allowed)
			(copperpour allowed)
			(footprints allowed)
		)
		(placement
			(enabled no)
			(sheetname "")
		)
		(fill
			(thermal_gap 0.5)
			(thermal_bridge_width 0.5)
			(island_removal_mode 0)
		)
		(polygon
			(pts
				(xy 207.154526 -286.026352) (xy 209.186526 -286.026352) (xy 209.186526 -286.254952) (xy 207.154526 -286.254952)
				(xy 207.018382 -286.254952) (xy 206.971392 -286.254952) (xy 206.971392 -286.026352) (xy 207.018382 -286.026352)
			)
		)
	)
	(zone
		(layer "F.Cu")
		(hatch none 0.5)
		(connect_pads
			(clearance 0)
		)
		(min_thickness 0.25)
		(keepout
			(tracks allowed)
			(vias allowed)
			(pads allowed)
			(copperpour allowed)
			(footprints allowed)
		)
		(placement
			(enabled no)
			(sheetname "")
		)
		(fill
			(thermal_gap 0.5)
			(thermal_bridge_width 0.5)
			(island_removal_mode 0)
		)
		(polygon
			(pts
				(xy 413.275526 -218.254834) (xy 413.275526 -218.026234) (xy 415.307526 -218.026234) (xy 415.307526 -218.254834)
			)
		)
	)
	(zone
		(layer "F.Cu")
		(hatch none 0.5)
		(connect_pads
			(clearance 0)
		)
		(min_thickness 0.25)
		(keepout
			(tracks allowed)
			(vias allowed)
			(pads allowed)
			(copperpour allowed)
			(footprints allowed)
		)
		(placement
			(enabled no)
			(sheetname "")
		)
		(fill
			(thermal_gap 0.5)
			(thermal_bridge_width 0.5)
			(island_removal_mode 0)
		)
		(polygon
			(pts
				(xy 11.11631 -224.316544) (xy 11.11631 -223.872806) (xy 13.441426 -223.872806) (xy 13.441426 -224.316544)
			)
		)
	)
	(zone
		(layer "F.Cu")
		(hatch none 0.5)
		(connect_pads
			(clearance 0)
		)
		(min_thickness 0.25)
		(keepout
			(tracks allowed)
			(vias allowed)
			(pads allowed)
			(copperpour allowed)
			(footprints allowed)
		)
		(placement
			(enabled no)
			(sheetname "")
		)
		(fill
			(thermal_gap 0.5)
			(thermal_bridge_width 0.5)
			(island_removal_mode 0)
		)
		(polygon
			(pts
				(xy 11.11631 -297.416474) (xy 11.11631 -296.972736) (xy 13.441426 -296.972736) (xy 13.441426 -297.416474)
			)
		)
	)
	(zone
		(layer "F.Cu")
		(hatch none 0.5)
		(connect_pads
			(clearance 0)
		)
		(min_thickness 0.25)
		(keepout
			(tracks not_allowed)
			(vias allowed)
			(pads allowed)
			(copperpour not_allowed)
			(footprints allowed)
		)
		(placement
			(enabled no)
			(sheetname "")
		)
		(fill
			(thermal_gap 0.5)
			(thermal_bridge_width 0.5)
			(island_removal_mode 0)
		)
		(polygon
			(pts
				(xy 414.116012 -364.631986) (xy 418.0586 -364.631986) (xy 418.0586 -364.566454) (xy 417.93922 -364.447074)
				(xy 416.503866 -364.447074) (xy 416.503866 -362.288074) (xy 418.66058 -362.288074) (xy 418.66058 -362.038392)
				(xy 416.333178 -362.038392) (xy 416.333178 -362.346494) (xy 416.212528 -362.346494) (xy 416.212528 -364.391448)
				(xy 414.358328 -364.391448) (xy 414.358328 -364.150402) (xy 414.116012 -364.150402)
			)
		)
	)
	(zone
		(layer "F.Cu")
		(hatch none 0.5)
		(connect_pads
			(clearance 0)
		)
		(min_thickness 0.25)
		(keepout
			(tracks allowed)
			(vias allowed)
			(pads allowed)
			(copperpour allowed)
			(footprints allowed)
		)
		(placement
			(enabled no)
			(sheetname "")
		)
		(fill
			(thermal_gap 0.5)
			(thermal_bridge_width 0.5)
			(island_removal_mode 0)
		)
		(polygon
			(pts
				(xy 207.154526 -303.25695) (xy 209.186526 -303.25695) (xy 209.186526 -303.02835) (xy 207.154526 -303.02835)
				(xy 207.023208 -303.02835) (xy 206.9973 -303.02835) (xy 206.9973 -303.25695) (xy 207.023208 -303.25695)
			)
		)
	)
	(zone
		(layer "F.Cu")
		(hatch none 0.5)
		(connect_pads
			(clearance 0)
		)
		(min_thickness 0.25)
		(keepout
			(tracks allowed)
			(vias allowed)
			(pads allowed)
			(copperpour allowed)
			(footprints allowed)
		)
		(placement
			(enabled no)
			(sheetname "")
		)
		(fill
			(thermal_gap 0.5)
			(thermal_bridge_width 0.5)
			(island_removal_mode 0)
		)
		(polygon
			(pts
				(xy 25.737566 -166.855394) (xy 25.737566 -162.819334) (xy 29.618686 -162.819334) (xy 29.618686 -166.855394)
			)
		)
	)
	(zone
		(layer "F.Cu")
		(hatch none 0.5)
		(connect_pads
			(clearance 0)
		)
		(min_thickness 0.25)
		(keepout
			(tracks allowed)
			(vias allowed)
			(pads allowed)
			(copperpour allowed)
			(footprints allowed)
		)
		(placement
			(enabled no)
			(sheetname "")
		)
		(fill
			(thermal_gap 0.5)
			(thermal_bridge_width 0.5)
			(island_removal_mode 0)
		)
		(polygon
			(pts
				(xy 41.29151 -229.41661) (xy 41.29151 -228.972872) (xy 43.616626 -228.972872) (xy 43.616626 -229.41661)
			)
		)
	)
	(zone
		(layer "F.Cu")
		(hatch none 0.5)
		(connect_pads
			(clearance 0)
		)
		(min_thickness 0.25)
		(keepout
			(tracks allowed)
			(vias allowed)
			(pads allowed)
			(copperpour allowed)
			(footprints allowed)
		)
		(placement
			(enabled no)
			(sheetname "")
		)
		(fill
			(thermal_gap 0.5)
			(thermal_bridge_width 0.5)
			(island_removal_mode 0)
		)
		(polygon
			(pts
				(xy 50.586132 -404.802594) (xy 50.586132 -399.959576) (xy 52.470558 -399.959576) (xy 52.470558 -404.802594)
			)
		)
	)
	(zone
		(layer "F.Cu")
		(hatch none 0.5)
		(connect_pads
			(clearance 0)
		)
		(min_thickness 0.25)
		(keepout
			(tracks allowed)
			(vias allowed)
			(pads allowed)
			(copperpour allowed)
			(footprints allowed)
		)
		(placement
			(enabled no)
			(sheetname "")
		)
		(fill
			(thermal_gap 0.5)
			(thermal_bridge_width 0.5)
			(island_removal_mode 0)
		)
		(polygon
			(pts
				(xy 136.360408 -410.948886) (xy 136.360408 -406.105868) (xy 138.244834 -406.105868) (xy 138.244834 -410.948886)
			)
		)
	)
	(zone
		(layer "F.Cu")
		(hatch none 0.5)
		(connect_pads
			(clearance 0)
		)
		(min_thickness 0.25)
		(keepout
			(tracks allowed)
			(vias allowed)
			(pads allowed)
			(copperpour allowed)
			(footprints allowed)
		)
		(placement
			(enabled no)
			(sheetname "")
		)
		(fill
			(thermal_gap 0.5)
			(thermal_bridge_width 0.5)
			(island_removal_mode 0)
		)
		(polygon
			(pts
				(xy 65.902332 -404.802594) (xy 65.902332 -399.959576) (xy 67.786758 -399.959576) (xy 67.786758 -404.802594)
			)
		)
	)
	(zone
		(layer "F.Cu")
		(hatch none 0.5)
		(connect_pads
			(clearance 0)
		)
		(min_thickness 0.25)
		(keepout
			(tracks not_allowed)
			(vias allowed)
			(pads allowed)
			(copperpour not_allowed)
			(footprints allowed)
		)
		(placement
			(enabled no)
			(sheetname "")
		)
		(fill
			(thermal_gap 0.5)
			(thermal_bridge_width 0.5)
			(island_removal_mode 0)
		)
		(polygon
			(pts
				(xy 351.053654 -336.26044) (xy 354.85324 -336.26044) (xy 354.85324 -336.075528) (xy 353.441508 -336.075528)
				(xy 353.441508 -333.916528) (xy 355.598222 -333.916528) (xy 355.598222 -333.666846) (xy 353.2632 -333.666846)
				(xy 353.2632 -333.820008) (xy 353.19716 -333.820008) (xy 353.19716 -333.883508) (xy 353.19462 -333.883508)
				(xy 353.19462 -333.997808) (xy 353.15017 -333.997808) (xy 353.15017 -336.019902) (xy 351.29597 -336.019902)
				(xy 351.29597 -335.778856) (xy 351.053654 -335.778856)
			)
		)
	)
	(zone
		(layer "F.Cu")
		(hatch none 0.5)
		(connect_pads
			(clearance 0)
		)
		(min_thickness 0.25)
		(keepout
			(tracks allowed)
			(vias allowed)
			(pads allowed)
			(copperpour allowed)
			(footprints allowed)
		)
		(placement
			(enabled no)
			(sheetname "")
		)
		(fill
			(thermal_gap 0.5)
			(thermal_bridge_width 0.5)
			(island_removal_mode 0)
		)
		(polygon
			(pts
				(xy 405.731726 -263.305036) (xy 405.731726 -263.076436) (xy 407.763726 -263.076436) (xy 407.763726 -263.305036)
			)
		)
	)
	(zone
		(layer "F.Cu")
		(hatch none 0.5)
		(connect_pads
			(clearance 0)
		)
		(min_thickness 0.25)
		(keepout
			(tracks allowed)
			(vias allowed)
			(pads allowed)
			(copperpour allowed)
			(footprints not_allowed)
		)
		(placement
			(enabled no)
			(sheetname "")
		)
		(fill
			(thermal_gap 0.5)
			(thermal_bridge_width 0.5)
			(island_removal_mode 0)
		)
		(polygon
			(pts
				(xy 254.080772 -185.091832) (xy 254.080772 -331.091794) (xy 314.987178 -331.091794) (xy 314.987178 -185.091832)
			)
		)
	)
	(zone
		(layer "F.Cu")
		(hatch none 0.5)
		(connect_pads
			(clearance 0)
		)
		(min_thickness 0.25)
		(keepout
			(tracks allowed)
			(vias allowed)
			(pads allowed)
			(copperpour allowed)
			(footprints allowed)
		)
		(placement
			(enabled no)
			(sheetname "")
		)
		(fill
			(thermal_gap 0.5)
			(thermal_bridge_width 0.5)
			(island_removal_mode 0)
		)
		(polygon
			(pts
				(xy 279.912826 -237.066582) (xy 277.58771 -237.066582) (xy 277.444708 -237.066582) (xy 277.444708 -235.873036)
				(xy 279.965404 -235.873036) (xy 279.965404 -237.066582)
			)
		)
	)
	(zone
		(layer "F.Cu")
		(hatch none 0.5)
		(connect_pads
			(clearance 0)
		)
		(min_thickness 0.25)
		(keepout
			(tracks allowed)
			(vias allowed)
			(pads allowed)
			(copperpour allowed)
			(footprints allowed)
		)
		(placement
			(enabled no)
			(sheetname "")
		)
		(fill
			(thermal_gap 0.5)
			(thermal_bridge_width 0.5)
			(island_removal_mode 0)
		)
		(polygon
			(pts
				(xy 29.647642 -248.966482) (xy 29.647642 -248.522744) (xy 31.972758 -248.522744) (xy 31.972758 -248.966482)
			)
		)
	)
	(zone
		(layer "F.Cu")
		(hatch none 0.5)
		(connect_pads
			(clearance 0)
		)
		(min_thickness 0.25)
		(keepout
			(tracks not_allowed)
			(vias allowed)
			(pads allowed)
			(copperpour not_allowed)
			(footprints allowed)
		)
		(placement
			(enabled no)
			(sheetname "")
		)
		(fill
			(thermal_gap 0.5)
			(thermal_bridge_width 0.5)
			(island_removal_mode 0)
		)
		(polygon
			(pts
				(arc
					(start 238.650018 -272.50009)
					(mid 236.650022 -274.500086)
					(end 234.650026 -272.50009)
				)
				(arc
					(start 234.650026 -272.50009)
					(mid 236.650022 -270.500094)
					(end 238.650018 -272.50009)
				)
			)
		)
	)
	(zone
		(layer "F.Cu")
		(hatch none 0.5)
		(connect_pads
			(clearance 0)
		)
		(min_thickness 0.25)
		(keepout
			(tracks allowed)
			(vias allowed)
			(pads allowed)
			(copperpour allowed)
			(footprints allowed)
		)
		(placement
			(enabled no)
			(sheetname "")
		)
		(fill
			(thermal_gap 0.5)
			(thermal_bridge_width 0.5)
			(island_removal_mode 0)
		)
		(polygon
			(pts
				(xy 424.919394 -240.976404) (xy 426.951394 -240.976404) (xy 426.951394 -241.205004) (xy 424.919394 -241.205004)
				(xy 424.78325 -241.205004) (xy 424.73626 -241.205004) (xy 424.73626 -240.976404) (xy 424.78325 -240.976404)
			)
		)
	)
	(zone
		(layer "F.Cu")
		(hatch none 0.5)
		(connect_pads
			(clearance 0)
		)
		(min_thickness 0.25)
		(keepout
			(tracks allowed)
			(vias allowed)
			(pads allowed)
			(copperpour allowed)
			(footprints allowed)
		)
		(placement
			(enabled no)
			(sheetname "")
		)
		(fill
			(thermal_gap 0.5)
			(thermal_bridge_width 0.5)
			(island_removal_mode 0)
		)
		(polygon
			(pts
				(xy 358.12222 -41.96334) (xy 358.12222 -40.42918) (xy 357.0478 -40.42918) (xy 357.0478 -41.96334)
			)
		)
	)
	(zone
		(layer "F.Cu")
		(hatch none 0.5)
		(connect_pads
			(clearance 0)
		)
		(min_thickness 0.25)
		(keepout
			(tracks allowed)
			(vias allowed)
			(pads allowed)
			(copperpour allowed)
			(footprints allowed)
		)
		(placement
			(enabled no)
			(sheetname "")
		)
		(fill
			(thermal_gap 0.5)
			(thermal_bridge_width 0.5)
			(island_removal_mode 0)
		)
		(polygon
			(pts
				(xy 22.103842 -268.516354) (xy 22.103842 -268.072616) (xy 22.103842 -267.659358) (xy 22.167342 -267.595858)
				(xy 24.46274 -267.595858) (xy 24.595582 -267.7287) (xy 24.595582 -268.467332) (xy 24.54656 -268.516354)
				(xy 24.428958 -268.516354)
			)
		)
	)
	(zone
		(layer "F.Cu")
		(hatch none 0.5)
		(connect_pads
			(clearance 0)
		)
		(min_thickness 0.25)
		(keepout
			(tracks allowed)
			(vias allowed)
			(pads allowed)
			(copperpour allowed)
			(footprints allowed)
		)
		(placement
			(enabled no)
			(sheetname "")
		)
		(fill
			(thermal_gap 0.5)
			(thermal_bridge_width 0.5)
			(island_removal_mode 0)
		)
		(polygon
			(pts
				(xy 90.62974 -359.593388) (xy 90.62974 -357.475028) (xy 95.2246 -357.475028) (xy 95.2246 -359.593388)
			)
		)
	)
	(zone
		(layer "F.Cu")
		(hatch none 0.5)
		(connect_pads
			(clearance 0)
		)
		(min_thickness 0.25)
		(keepout
			(tracks allowed)
			(vias allowed)
			(pads allowed)
			(copperpour allowed)
			(footprints allowed)
		)
		(placement
			(enabled no)
			(sheetname "")
		)
		(fill
			(thermal_gap 0.5)
			(thermal_bridge_width 0.5)
			(island_removal_mode 0)
		)
		(polygon
			(pts
				(xy 440.006994 -216.326466) (xy 442.038994 -216.326466) (xy 442.038994 -216.555066) (xy 440.006994 -216.555066)
				(xy 439.87085 -216.555066) (xy 439.82386 -216.555066) (xy 439.82386 -216.326466) (xy 439.87085 -216.326466)
			)
		)
	)
	(zone
		(layer "F.Cu")
		(hatch none 0.5)
		(connect_pads
			(clearance 0)
		)
		(min_thickness 0.25)
		(keepout
			(tracks allowed)
			(vias allowed)
			(pads allowed)
			(copperpour allowed)
			(footprints allowed)
		)
		(placement
			(enabled no)
			(sheetname "")
		)
		(fill
			(thermal_gap 0.5)
			(thermal_bridge_width 0.5)
			(island_removal_mode 0)
		)
		(polygon
			(pts
				(xy 41.29151 -280.416508) (xy 41.29151 -279.97277) (xy 43.616626 -279.97277) (xy 43.616626 -280.416508)
			)
		)
	)
	(zone
		(layer "F.Cu")
		(hatch none 0.5)
		(connect_pads
			(clearance 0)
		)
		(min_thickness 0.25)
		(keepout
			(tracks allowed)
			(vias allowed)
			(pads allowed)
			(copperpour allowed)
			(footprints allowed)
		)
		(placement
			(enabled no)
			(sheetname "")
		)
		(fill
			(thermal_gap 0.5)
			(thermal_bridge_width 0.5)
			(island_removal_mode 0)
		)
		(polygon
			(pts
				(xy 14.560042 -239.616488) (xy 14.560042 -239.17275) (xy 16.885158 -239.17275) (xy 16.885158 -239.616488)
			)
		)
	)
	(zone
		(layer "F.Cu")
		(hatch none 0.5)
		(connect_pads
			(clearance 0)
		)
		(min_thickness 0.25)
		(keepout
			(tracks allowed)
			(vias allowed)
			(pads allowed)
			(copperpour allowed)
			(footprints allowed)
		)
		(placement
			(enabled no)
			(sheetname "")
		)
		(fill
			(thermal_gap 0.5)
			(thermal_bridge_width 0.5)
			(island_removal_mode 0)
		)
		(polygon
			(pts
				(xy 207.154526 -229.07625) (xy 209.186526 -229.07625) (xy 209.186526 -229.30485) (xy 207.154526 -229.30485)
				(xy 207.023208 -229.30485) (xy 206.9973 -229.30485) (xy 206.9973 -229.07625) (xy 207.023208 -229.07625)
			)
		)
	)
	(zone
		(layer "F.Cu")
		(hatch none 0.5)
		(connect_pads
			(clearance 0)
		)
		(min_thickness 0.25)
		(keepout
			(tracks allowed)
			(vias allowed)
			(pads allowed)
			(copperpour allowed)
			(footprints allowed)
		)
		(placement
			(enabled no)
			(sheetname "")
		)
		(fill
			(thermal_gap 0.5)
			(thermal_bridge_width 0.5)
			(island_removal_mode 0)
		)
		(polygon
			(pts
				(xy 259.056378 -260.866636) (xy 259.056378 -260.422898) (xy 261.381494 -260.422898) (xy 261.381494 -260.866636)
			)
		)
	)
	(zone
		(layer "F.Cu")
		(hatch none 0.5)
		(connect_pads
			(clearance 0)
		)
		(min_thickness 0.25)
		(keepout
			(tracks allowed)
			(vias allowed)
			(pads allowed)
			(copperpour allowed)
			(footprints allowed)
		)
		(placement
			(enabled no)
			(sheetname "")
		)
		(fill
			(thermal_gap 0.5)
			(thermal_bridge_width 0.5)
			(island_removal_mode 0)
		)
		(polygon
			(pts
				(xy 207.154526 -313.226196) (xy 209.186526 -313.226196) (xy 209.186526 -313.454796) (xy 207.154526 -313.454796)
				(xy 207.023208 -313.454796) (xy 206.9973 -313.454796) (xy 206.9973 -313.226196) (xy 207.023208 -313.226196)
			)
		)
	)
	(zone
		(layer "F.Cu")
		(hatch none 0.5)
		(connect_pads
			(clearance 0)
		)
		(min_thickness 0.25)
		(keepout
			(tracks allowed)
			(vias allowed)
			(pads allowed)
			(copperpour allowed)
			(footprints allowed)
		)
		(placement
			(enabled no)
			(sheetname "")
		)
		(fill
			(thermal_gap 0.5)
			(thermal_bridge_width 0.5)
			(island_removal_mode 0)
		)
		(polygon
			(pts
				(xy 405.731726 -314.304934) (xy 405.731726 -314.076334) (xy 407.763726 -314.076334) (xy 407.763726 -314.304934)
			)
		)
	)
	(zone
		(layer "F.Cu")
		(hatch none 0.5)
		(connect_pads
			(clearance 0)
		)
		(min_thickness 0.25)
		(keepout
			(tracks allowed)
			(vias allowed)
			(pads allowed)
			(copperpour allowed)
			(footprints allowed)
		)
		(placement
			(enabled no)
			(sheetname "")
		)
		(fill
			(thermal_gap 0.5)
			(thermal_bridge_width 0.5)
			(island_removal_mode 0)
		)
		(polygon
			(pts
				(xy 252.95352 -52.217066) (xy 252.95352 -48.231806) (xy 254.70104 -48.231806) (xy 254.70104 -52.217066)
			)
		)
	)
	(zone
		(layer "F.Cu")
		(hatch none 0.5)
		(connect_pads
			(clearance 0)
		)
		(min_thickness 0.25)
		(keepout
			(tracks allowed)
			(vias allowed)
			(pads allowed)
			(copperpour allowed)
			(footprints allowed)
		)
		(placement
			(enabled no)
			(sheetname "")
		)
		(fill
			(thermal_gap 0.5)
			(thermal_bridge_width 0.5)
			(island_removal_mode 0)
		)
		(polygon
			(pts
				(xy 458.538326 -196.154802) (xy 458.538326 -195.926202) (xy 460.570326 -195.926202) (xy 460.570326 -196.154802)
			)
		)
	)
	(zone
		(layer "F.Cu")
		(hatch none 0.5)
		(connect_pads
			(clearance 0)
		)
		(min_thickness 0.25)
		(keepout
			(tracks allowed)
			(vias allowed)
			(pads allowed)
			(copperpour allowed)
			(footprints allowed)
		)
		(placement
			(enabled no)
			(sheetname "")
		)
		(fill
			(thermal_gap 0.5)
			(thermal_bridge_width 0.5)
			(island_removal_mode 0)
		)
		(polygon
			(pts
				(xy 458.538326 -227.604828) (xy 458.538326 -227.376228) (xy 460.570326 -227.376228) (xy 460.570326 -227.604828)
			)
		)
	)
	(zone
		(layer "F.Cu")
		(hatch none 0.5)
		(connect_pads
			(clearance 0)
		)
		(min_thickness 0.25)
		(keepout
			(tracks allowed)
			(vias allowed)
			(pads allowed)
			(copperpour allowed)
			(footprints allowed)
		)
		(placement
			(enabled no)
			(sheetname "")
		)
		(fill
			(thermal_gap 0.5)
			(thermal_bridge_width 0.5)
			(island_removal_mode 0)
		)
		(polygon
			(pts
				(xy 159.834834 -280.307034) (xy 157.802834 -280.307034) (xy 157.802834 -280.304748) (xy 157.624018 -280.304748)
				(xy 157.624018 -280.067512) (xy 157.486096 -280.067512) (xy 157.442916 -280.024332) (xy 157.442916 -279.89149)
				(xy 157.442916 -279.587452) (xy 157.51556 -279.514808) (xy 160.055814 -279.514808) (xy 160.197038 -279.656032)
				(xy 160.197038 -279.853136) (xy 160.115504 -279.93467) (xy 160.115504 -280.307034) (xy 160.017968 -280.307034)
				(xy 159.970978 -280.307034)
			)
		)
	)
	(zone
		(layer "F.Cu")
		(hatch none 0.5)
		(connect_pads
			(clearance 0)
		)
		(min_thickness 0.25)
		(keepout
			(tracks allowed)
			(vias allowed)
			(pads allowed)
			(copperpour allowed)
			(footprints allowed)
		)
		(placement
			(enabled no)
			(sheetname "")
		)
		(fill
			(thermal_gap 0.5)
			(thermal_bridge_width 0.5)
			(island_removal_mode 0)
		)
		(polygon
			(pts
				(xy 40.680386 -352.740214) (xy 38.864286 -352.740214) (xy 38.864286 -351.360994) (xy 40.680386 -351.360994)
			)
		)
	)
	(zone
		(layer "F.Cu")
		(hatch none 0.5)
		(connect_pads
			(clearance 0)
		)
		(min_thickness 0.25)
		(keepout
			(tracks allowed)
			(vias allowed)
			(pads allowed)
			(copperpour allowed)
			(footprints allowed)
		)
		(placement
			(enabled no)
			(sheetname "")
		)
		(fill
			(thermal_gap 0.5)
			(thermal_bridge_width 0.5)
			(island_removal_mode 0)
		)
		(polygon
			(pts
				(xy 300.20006 -269.375128) (xy 300.20006 -268.93139) (xy 302.525176 -268.93139) (xy 302.525176 -269.375128)
			)
		)
	)
	(zone
		(layer "F.Cu")
		(hatch none 0.5)
		(connect_pads
			(clearance 0)
		)
		(min_thickness 0.25)
		(keepout
			(tracks allowed)
			(vias allowed)
			(pads allowed)
			(copperpour allowed)
			(footprints not_allowed)
		)
		(placement
			(enabled no)
			(sheetname "")
		)
		(fill
			(thermal_gap 0.5)
			(thermal_bridge_width 0.5)
			(island_removal_mode 0)
		)
		(polygon
			(pts
				(xy 262.62457 -330.091796) (xy 268.72438 -330.091796) (xy 268.72438 -186.09183) (xy 262.62457 -186.09183)
			)
		)
	)
	(zone
		(layer "F.Cu")
		(hatch none 0.5)
		(connect_pads
			(clearance 0)
		)
		(min_thickness 0.25)
		(keepout
			(tracks allowed)
			(vias allowed)
			(pads allowed)
			(copperpour allowed)
			(footprints allowed)
		)
		(placement
			(enabled no)
			(sheetname "")
		)
		(fill
			(thermal_gap 0.5)
			(thermal_bridge_width 0.5)
			(island_removal_mode 0)
		)
		(polygon
			(pts
				(xy 274.143978 -264.266426) (xy 274.143978 -263.822688) (xy 276.469094 -263.822688) (xy 276.469094 -264.266426)
			)
		)
	)
	(zone
		(layer "F.Cu")
		(hatch none 0.5)
		(connect_pads
			(clearance 0)
		)
		(min_thickness 0.25)
		(keepout
			(tracks allowed)
			(vias allowed)
			(pads allowed)
			(copperpour allowed)
			(footprints allowed)
		)
		(placement
			(enabled no)
			(sheetname "")
		)
		(fill
			(thermal_gap 0.5)
			(thermal_bridge_width 0.5)
			(island_removal_mode 0)
		)
		(polygon
			(pts
				(xy 289.231578 -259.166614) (xy 289.231578 -258.722876) (xy 291.556694 -258.722876) (xy 291.556694 -259.166614)
			)
		)
	)
	(zone
		(layer "F.Cu")
		(hatch none 0.5)
		(connect_pads
			(clearance 0)
		)
		(min_thickness 0.25)
		(keepout
			(tracks allowed)
			(vias allowed)
			(pads allowed)
			(copperpour allowed)
			(footprints allowed)
		)
		(placement
			(enabled no)
			(sheetname "")
		)
		(fill
			(thermal_gap 0.5)
			(thermal_bridge_width 0.5)
			(island_removal_mode 0)
		)
		(polygon
			(pts
				(xy 10.845038 -269.919704) (xy 17.112234 -269.919704) (xy 17.271746 -269.760192) (xy 17.271746 -268.496034)
				(xy 17.125442 -268.34973) (xy 11.018012 -268.34973) (xy 10.845038 -268.522704)
			)
		)
	)
	(zone
		(layer "F.Cu")
		(hatch none 0.5)
		(connect_pads
			(clearance 0)
		)
		(min_thickness 0.25)
		(keepout
			(tracks allowed)
			(vias allowed)
			(pads allowed)
			(copperpour allowed)
			(footprints allowed)
		)
		(placement
			(enabled no)
			(sheetname "")
		)
		(fill
			(thermal_gap 0.5)
			(thermal_bridge_width 0.5)
			(island_removal_mode 0)
		)
		(polygon
			(pts
				(xy 311.89168 -239.17275) (xy 314.15228 -239.17275) (xy 314.248292 -239.17275) (xy 314.248292 -240.088674)
				(xy 311.747662 -240.088674) (xy 311.747662 -239.17275)
			)
		)
	)
	(zone
		(layer "F.Cu")
		(hatch none 0.5)
		(connect_pads
			(clearance 0)
		)
		(min_thickness 0.25)
		(keepout
			(tracks allowed)
			(vias allowed)
			(pads allowed)
			(copperpour allowed)
			(footprints allowed)
		)
		(placement
			(enabled no)
			(sheetname "")
		)
		(fill
			(thermal_gap 0.5)
			(thermal_bridge_width 0.5)
			(island_removal_mode 0)
		)
		(polygon
			(pts
				(xy 413.966406 -351.202752) (xy 413.966406 -348.341188) (xy 418.337746 -348.341188) (xy 418.337746 -351.202752)
			)
		)
	)
	(zone
		(layer "F.Cu")
		(hatch none 0.5)
		(connect_pads
			(clearance 0)
		)
		(min_thickness 0.25)
		(keepout
			(tracks allowed)
			(vias allowed)
			(pads allowed)
			(copperpour allowed)
			(footprints allowed)
		)
		(placement
			(enabled no)
			(sheetname "")
		)
		(fill
			(thermal_gap 0.5)
			(thermal_bridge_width 0.5)
			(island_removal_mode 0)
		)
		(polygon
			(pts
				(xy 180.423058 -273.504914) (xy 180.423058 -273.276314) (xy 182.455058 -273.276314) (xy 182.455058 -273.504914)
			)
		)
	)
	(zone
		(layer "F.Cu")
		(hatch none 0.5)
		(connect_pads
			(clearance 0)
		)
		(min_thickness 0.25)
		(keepout
			(tracks allowed)
			(vias allowed)
			(pads allowed)
			(copperpour allowed)
			(footprints allowed)
		)
		(placement
			(enabled no)
			(sheetname "")
		)
		(fill
			(thermal_gap 0.5)
			(thermal_bridge_width 0.5)
			(island_removal_mode 0)
		)
		(polygon
			(pts
				(xy 29.647642 -226.86645) (xy 29.647642 -226.422712) (xy 31.972758 -226.422712) (xy 31.972758 -226.86645)
			)
		)
	)
	(zone
		(layer "F.Cu")
		(hatch none 0.5)
		(connect_pads
			(clearance 0)
		)
		(min_thickness 0.25)
		(keepout
			(tracks allowed)
			(vias allowed)
			(pads allowed)
			(copperpour allowed)
			(footprints allowed)
		)
		(placement
			(enabled no)
			(sheetname "")
		)
		(fill
			(thermal_gap 0.5)
			(thermal_bridge_width 0.5)
			(island_removal_mode 0)
		)
		(polygon
			(pts
				(xy 405.731726 -268.404848) (xy 405.731726 -268.176248) (xy 407.763726 -268.176248) (xy 407.763726 -268.404848)
			)
		)
	)
	(zone
		(layer "F.Cu")
		(hatch none 0.5)
		(connect_pads
			(clearance 0)
		)
		(min_thickness 0.25)
		(keepout
			(tracks allowed)
			(vias allowed)
			(pads allowed)
			(copperpour allowed)
			(footprints allowed)
		)
		(placement
			(enabled no)
			(sheetname "")
		)
		(fill
			(thermal_gap 0.5)
			(thermal_bridge_width 0.5)
			(island_removal_mode 0)
		)
		(polygon
			(pts
				(xy 207.154526 -293.906956) (xy 209.186526 -293.906956) (xy 209.186526 -293.678356) (xy 207.154526 -293.678356)
				(xy 207.023208 -293.678356) (xy 206.9973 -293.678356) (xy 206.9973 -293.906956) (xy 207.023208 -293.906956)
			)
		)
	)
	(zone
		(layer "F.Cu")
		(hatch none 0.5)
		(connect_pads
			(clearance 0)
		)
		(min_thickness 0.25)
		(keepout
			(tracks allowed)
			(vias allowed)
			(pads allowed)
			(copperpour allowed)
			(footprints allowed)
		)
		(placement
			(enabled no)
			(sheetname "")
		)
		(fill
			(thermal_gap 0.5)
			(thermal_bridge_width 0.5)
			(island_removal_mode 0)
		)
		(polygon
			(pts
				(xy 7.559548 -316.668658) (xy 63.257684 -316.668658) (xy 63.359284 -316.668658) (xy 66.61404 -316.668658)
				(xy 66.857372 -316.668658) (xy 66.977514 -316.548516) (xy 66.977514 -314.826904) (xy 66.977514 -309.818532)
				(xy 66.977514 -309.235348) (xy 66.546222 -308.804056) (xy 66.546222 -297.694096) (xy 66.759836 -297.480482)
				(xy 66.759836 -295.967912) (xy 66.546222 -295.754298) (xy 66.546222 -288.263076) (xy 66.615564 -288.193734)
				(xy 66.615564 -286.610298) (xy 66.615564 -285.095696) (xy 66.900552 -284.810708) (xy 66.900552 -281.283664)
				(xy 66.745104 -281.128216) (xy 66.615564 -280.998676) (xy 66.615564 -279.116536) (xy 66.821304 -278.910796)
				(xy 66.821304 -277.539196) (xy 66.615564 -277.333456) (xy 66.615564 -273.599656) (xy 66.920364 -273.294856)
				(xy 66.920364 -271.407636) (xy 66.615564 -271.102836) (xy 66.615564 -268.67993) (xy 67.131438 -268.164056)
				(xy 67.131438 -267.00607) (xy 66.615564 -266.490196) (xy 66.615564 -258.675886) (xy 66.546222 -258.606544)
				(xy 66.140838 -258.20116) (xy 7.612126 -258.20116) (xy 7.506462 -258.306824) (xy 7.506462 -316.615572)
			)
		)
	)
	(zone
		(layer "F.Cu")
		(hatch none 0.5)
		(connect_pads
			(clearance 0)
		)
		(min_thickness 0.25)
		(keepout
			(tracks allowed)
			(vias allowed)
			(pads allowed)
			(copperpour allowed)
			(footprints allowed)
		)
		(placement
			(enabled no)
			(sheetname "")
		)
		(fill
			(thermal_gap 0.5)
			(thermal_bridge_width 0.5)
			(island_removal_mode 0)
		)
		(polygon
			(pts
				(xy 157.791658 -252.25502) (xy 157.791658 -252.02642) (xy 159.823658 -252.02642) (xy 159.823658 -252.25502)
			)
		)
	)
	(zone
		(layer "F.Cu")
		(hatch none 0.5)
		(connect_pads
			(clearance 0)
		)
		(min_thickness 0.25)
		(keepout
			(tracks allowed)
			(vias allowed)
			(pads allowed)
			(copperpour allowed)
			(footprints allowed)
		)
		(placement
			(enabled no)
			(sheetname "")
		)
		(fill
			(thermal_gap 0.5)
			(thermal_bridge_width 0.5)
			(island_removal_mode 0)
		)
		(polygon
			(pts
				(xy 411.863794 -238.654844) (xy 409.831794 -238.654844) (xy 409.42768 -238.654844) (xy 409.42768 -237.584742)
				(xy 412.278576 -237.584742) (xy 412.278576 -238.654844)
			)
		)
	)
	(zone
		(layer "F.Cu")
		(hatch none 0.5)
		(connect_pads
			(clearance 0)
		)
		(min_thickness 0.25)
		(keepout
			(tracks allowed)
			(vias allowed)
			(pads allowed)
			(copperpour allowed)
			(footprints allowed)
		)
		(placement
			(enabled no)
			(sheetname "")
		)
		(fill
			(thermal_gap 0.5)
			(thermal_bridge_width 0.5)
			(island_removal_mode 0)
		)
		(polygon
			(pts
				(xy 445.493902 -272.657062) (xy 443.461902 -272.657062) (xy 443.461902 -272.654776) (xy 443.283086 -272.654776)
				(xy 443.283086 -272.41754) (xy 443.145164 -272.41754) (xy 443.101984 -272.37436) (xy 443.101984 -272.241518)
				(xy 443.101984 -271.93748) (xy 443.174628 -271.864836) (xy 445.714882 -271.864836) (xy 445.856106 -272.00606)
				(xy 445.856106 -272.203164) (xy 445.774572 -272.284698) (xy 445.774572 -272.657062) (xy 445.677036 -272.657062)
				(xy 445.630046 -272.657062)
			)
		)
	)
	(zone
		(layer "F.Cu")
		(hatch none 0.5)
		(connect_pads
			(clearance 0)
		)
		(min_thickness 0.25)
		(keepout
			(tracks allowed)
			(vias allowed)
			(pads allowed)
			(copperpour allowed)
			(footprints not_allowed)
		)
		(placement
			(enabled no)
			(sheetname "")
		)
		(fill
			(thermal_gap 0.5)
			(thermal_bridge_width 0.5)
			(island_removal_mode 0)
		)
		(polygon
			(pts
				(arc
					(start 5.340096 -160.50006)
					(mid 10.340086 -155.50007)
					(end 15.340076 -160.50006)
				)
				(arc
					(start 15.340076 -160.50006)
					(mid 10.340086 -165.50005)
					(end 5.340096 -160.50006)
				)
			)
		)
	)
	(zone
		(layer "F.Cu")
		(hatch none 0.5)
		(connect_pads
			(clearance 0)
		)
		(min_thickness 0.25)
		(keepout
			(tracks allowed)
			(vias allowed)
			(pads allowed)
			(copperpour allowed)
			(footprints allowed)
		)
		(placement
			(enabled no)
			(sheetname "")
		)
		(fill
			(thermal_gap 0.5)
			(thermal_bridge_width 0.5)
			(island_removal_mode 0)
		)
		(polygon
			(pts
				(xy 418.095176 -179.078128) (xy 416.7632 -179.078128) (xy 416.564318 -178.879246) (xy 416.564318 -177.087276)
				(xy 417.367466 -176.284128) (xy 419.84549 -176.284128) (xy 421.205152 -177.64379) (xy 421.205152 -183.135524)
				(xy 420.065454 -184.275222) (xy 416.144964 -184.275222) (xy 415.51352 -183.643778) (xy 415.51352 -181.927754)
				(xy 416.070034 -181.37124) (xy 418.21862 -181.37124) (xy 418.2872 -181.30266) (xy 418.2872 -179.270152)
			)
		)
	)
	(zone
		(layer "F.Cu")
		(hatch none 0.5)
		(connect_pads
			(clearance 0)
		)
		(min_thickness 0.25)
		(keepout
			(tracks allowed)
			(vias allowed)
			(pads allowed)
			(copperpour allowed)
			(footprints allowed)
		)
		(placement
			(enabled no)
			(sheetname "")
		)
		(fill
			(thermal_gap 0.5)
			(thermal_bridge_width 0.5)
			(island_removal_mode 0)
		)
		(polygon
			(pts
				(xy 26.20391 -247.26646) (xy 26.20391 -246.822722) (xy 28.529026 -246.822722) (xy 28.529026 -247.26646)
			)
		)
	)
	(zone
		(layer "F.Cu")
		(hatch none 0.5)
		(connect_pads
			(clearance 0)
		)
		(min_thickness 0.25)
		(keepout
			(tracks allowed)
			(vias allowed)
			(pads allowed)
			(copperpour allowed)
			(footprints allowed)
		)
		(placement
			(enabled no)
			(sheetname "")
		)
		(fill
			(thermal_gap 0.5)
			(thermal_bridge_width 0.5)
			(island_removal_mode 0)
		)
		(polygon
			(pts
				(xy 41.29151 -231.966516) (xy 41.29151 -231.522778) (xy 43.616626 -231.522778) (xy 43.616626 -231.966516)
			)
		)
	)
	(zone
		(layer "F.Cu")
		(hatch none 0.5)
		(connect_pads
			(clearance 0)
		)
		(min_thickness 0.25)
		(keepout
			(tracks allowed)
			(vias allowed)
			(pads allowed)
			(copperpour allowed)
			(footprints allowed)
		)
		(placement
			(enabled no)
			(sheetname "")
		)
		(fill
			(thermal_gap 0.5)
			(thermal_bridge_width 0.5)
			(island_removal_mode 0)
		)
		(polygon
			(pts
				(xy 185.45048 -18.329148) (xy 185.45048 -15.230348) (xy 187.71616 -15.230348) (xy 187.71616 -18.329148)
			)
		)
	)
	(zone
		(layer "F.Cu")
		(hatch none 0.5)
		(connect_pads
			(clearance 0)
		)
		(min_thickness 0.25)
		(keepout
			(tracks allowed)
			(vias allowed)
			(pads allowed)
			(copperpour allowed)
			(footprints allowed)
		)
		(placement
			(enabled no)
			(sheetname "")
		)
		(fill
			(thermal_gap 0.5)
			(thermal_bridge_width 0.5)
			(island_removal_mode 0)
		)
		(polygon
			(pts
				(xy 180.423058 -274.354798) (xy 180.423058 -274.126198) (xy 182.455058 -274.126198) (xy 182.455058 -274.354798)
			)
		)
	)
	(zone
		(layer "F.Cu")
		(hatch none 0.5)
		(connect_pads
			(clearance 0)
		)
		(min_thickness 0.25)
		(keepout
			(tracks not_allowed)
			(vias allowed)
			(pads allowed)
			(copperpour not_allowed)
			(footprints allowed)
		)
		(placement
			(enabled no)
			(sheetname "")
		)
		(fill
			(thermal_gap 0.5)
			(thermal_bridge_width 0.5)
			(island_removal_mode 0)
		)
		(polygon
			(pts
				(xy 438.768744 -9.0424) (xy 438.944004 -9.0424) (xy 438.971944 -9.01446) (xy 438.971944 -7.62) (xy 438.949084 -7.59714)
				(xy 438.778904 -7.59714) (xy 438.758584 -7.61746) (xy 438.758584 -9.03224)
			)
		)
	)
	(zone
		(layer "F.Cu")
		(hatch none 0.5)
		(connect_pads
			(clearance 0)
		)
		(min_thickness 0.25)
		(keepout
			(tracks allowed)
			(vias allowed)
			(pads allowed)
			(copperpour allowed)
			(footprints allowed)
		)
		(placement
			(enabled no)
			(sheetname "")
		)
		(fill
			(thermal_gap 0.5)
			(thermal_bridge_width 0.5)
			(island_removal_mode 0)
		)
		(polygon
			(pts
				(xy 165.335458 -311.755028) (xy 165.335458 -311.526428) (xy 167.367458 -311.526428) (xy 167.367458 -311.755028)
			)
		)
	)
	(zone
		(layer "F.Cu")
		(hatch none 0.5)
		(connect_pads
			(clearance 0)
		)
		(min_thickness 0.25)
		(keepout
			(tracks allowed)
			(vias allowed)
			(pads allowed)
			(copperpour allowed)
			(footprints allowed)
		)
		(placement
			(enabled no)
			(sheetname "")
		)
		(fill
			(thermal_gap 0.5)
			(thermal_bridge_width 0.5)
			(island_removal_mode 0)
		)
		(polygon
			(pts
				(xy 307.76291 -248.966482) (xy 307.76291 -248.522744) (xy 310.088026 -248.522744) (xy 310.088026 -248.966482)
			)
		)
	)
	(zone
		(layer "F.Cu")
		(hatch none 0.5)
		(connect_pads
			(clearance 0)
		)
		(min_thickness 0.25)
		(keepout
			(tracks allowed)
			(vias allowed)
			(pads allowed)
			(copperpour allowed)
			(footprints allowed)
		)
		(placement
			(enabled no)
			(sheetname "")
		)
		(fill
			(thermal_gap 0.5)
			(thermal_bridge_width 0.5)
			(island_removal_mode 0)
		)
		(polygon
			(pts
				(xy 161.891726 -196.154802) (xy 161.891726 -195.926202) (xy 163.923726 -195.926202) (xy 163.923726 -196.154802)
			)
		)
	)
	(zone
		(layer "F.Cu")
		(hatch none 0.5)
		(connect_pads
			(clearance 0)
		)
		(min_thickness 0.25)
		(keepout
			(tracks allowed)
			(vias allowed)
			(pads allowed)
			(copperpour allowed)
			(footprints allowed)
		)
		(placement
			(enabled no)
			(sheetname "")
		)
		(fill
			(thermal_gap 0.5)
			(thermal_bridge_width 0.5)
			(island_removal_mode 0)
		)
		(polygon
			(pts
				(xy 440.006994 -297.076368) (xy 442.038994 -297.076368) (xy 442.038994 -297.304968) (xy 440.006994 -297.304968)
				(xy 439.87085 -297.304968) (xy 439.82386 -297.304968) (xy 439.82386 -297.076368) (xy 439.87085 -297.076368)
			)
		)
	)
	(zone
		(layer "F.Cu")
		(hatch none 0.5)
		(connect_pads
			(clearance 0)
		)
		(min_thickness 0.25)
		(keepout
			(tracks allowed)
			(vias allowed)
			(pads allowed)
			(copperpour allowed)
			(footprints allowed)
		)
		(placement
			(enabled no)
			(sheetname "")
		)
		(fill
			(thermal_gap 0.5)
			(thermal_bridge_width 0.5)
			(island_removal_mode 0)
		)
		(polygon
			(pts
				(xy 56.37911 -313.566556) (xy 56.37911 -313.122818) (xy 58.704226 -313.122818) (xy 58.704226 -313.566556)
			)
		)
	)
	(zone
		(layer "F.Cu")
		(hatch none 0.5)
		(connect_pads
			(clearance 0)
		)
		(min_thickness 0.25)
		(keepout
			(tracks allowed)
			(vias allowed)
			(pads allowed)
			(copperpour allowed)
			(footprints allowed)
		)
		(placement
			(enabled no)
			(sheetname "")
		)
		(fill
			(thermal_gap 0.5)
			(thermal_bridge_width 0.5)
			(island_removal_mode 0)
		)
		(polygon
			(pts
				(xy 59.822842 -202.216512) (xy 59.822842 -201.772774) (xy 62.147958 -201.772774) (xy 62.147958 -202.216512)
			)
		)
	)
	(zone
		(layer "F.Cu")
		(hatch none 0.5)
		(connect_pads
			(clearance 0)
		)
		(min_thickness 0.25)
		(keepout
			(tracks allowed)
			(vias allowed)
			(pads allowed)
			(copperpour allowed)
			(footprints allowed)
		)
		(placement
			(enabled no)
			(sheetname "")
		)
		(fill
			(thermal_gap 0.5)
			(thermal_bridge_width 0.5)
			(island_removal_mode 0)
		)
		(polygon
			(pts
				(xy 29.647642 -214.96655) (xy 29.647642 -214.522812) (xy 31.972758 -214.522812) (xy 31.972758 -214.96655)
			)
		)
	)
	(zone
		(layer "F.Cu")
		(hatch none 0.5)
		(connect_pads
			(clearance 0)
		)
		(min_thickness 0.25)
		(keepout
			(tracks allowed)
			(vias allowed)
			(pads allowed)
			(copperpour allowed)
			(footprints allowed)
		)
		(placement
			(enabled no)
			(sheetname "")
		)
		(fill
			(thermal_gap 0.5)
			(thermal_bridge_width 0.5)
			(island_removal_mode 0)
		)
		(polygon
			(pts
				(xy 29.647642 -199.666606) (xy 29.647642 -199.222868) (xy 31.972758 -199.222868) (xy 31.972758 -199.666606)
			)
		)
	)
	(zone
		(layer "F.Cu")
		(hatch none 0.5)
		(connect_pads
			(clearance 0)
		)
		(min_thickness 0.25)
		(keepout
			(tracks allowed)
			(vias allowed)
			(pads allowed)
			(copperpour allowed)
			(footprints allowed)
		)
		(placement
			(enabled no)
			(sheetname "")
		)
		(fill
			(thermal_gap 0.5)
			(thermal_bridge_width 0.5)
			(island_removal_mode 0)
		)
		(polygon
			(pts
				(xy 210.598258 -265.854942) (xy 210.598258 -265.626342) (xy 212.630258 -265.626342) (xy 212.630258 -265.854942)
			)
		)
	)
	(zone
		(layer "F.Cu")
		(hatch none 0.5)
		(connect_pads
			(clearance 0)
		)
		(min_thickness 0.25)
		(keepout
			(tracks allowed)
			(vias allowed)
			(pads allowed)
			(copperpour allowed)
			(footprints allowed)
		)
		(placement
			(enabled no)
			(sheetname "")
		)
		(fill
			(thermal_gap 0.5)
			(thermal_bridge_width 0.5)
			(island_removal_mode 0)
		)
		(polygon
			(pts
				(xy 210.598258 -236.954822) (xy 210.598258 -236.726222) (xy 212.630258 -236.726222) (xy 212.630258 -236.954822)
			)
		)
	)
	(zone
		(layer "F.Cu")
		(hatch none 0.5)
		(connect_pads
			(clearance 0)
		)
		(min_thickness 0.25)
		(keepout
			(tracks allowed)
			(vias allowed)
			(pads allowed)
			(copperpour allowed)
			(footprints allowed)
		)
		(placement
			(enabled no)
			(sheetname "")
		)
		(fill
			(thermal_gap 0.5)
			(thermal_bridge_width 0.5)
			(island_removal_mode 0)
		)
		(polygon
			(pts
				(xy 259.056378 -214.96655) (xy 259.056378 -214.522812) (xy 261.381494 -214.522812) (xy 261.381494 -214.96655)
			)
		)
	)
	(zone
		(layer "F.Cu")
		(hatch none 0.5)
		(connect_pads
			(clearance 0)
		)
		(min_thickness 0.25)
		(keepout
			(tracks allowed)
			(vias allowed)
			(pads allowed)
			(copperpour allowed)
			(footprints allowed)
		)
		(placement
			(enabled no)
			(sheetname "")
		)
		(fill
			(thermal_gap 0.5)
			(thermal_bridge_width 0.5)
			(island_removal_mode 0)
		)
		(polygon
			(pts
				(xy 192.066926 -315.776356) (xy 194.098926 -315.776356) (xy 194.098926 -316.004956) (xy 192.066926 -316.004956)
				(xy 191.930782 -316.004956) (xy 191.883792 -316.004956) (xy 191.883792 -315.776356) (xy 191.930782 -315.776356)
			)
		)
	)
	(zone
		(layer "F.Cu")
		(hatch none 0.5)
		(connect_pads
			(clearance 0)
		)
		(min_thickness 0.25)
		(keepout
			(tracks not_allowed)
			(vias allowed)
			(pads allowed)
			(copperpour not_allowed)
			(footprints allowed)
		)
		(placement
			(enabled no)
			(sheetname "")
		)
		(fill
			(thermal_gap 0.5)
			(thermal_bridge_width 0.5)
			(island_removal_mode 0)
		)
		(polygon
			(pts
				(xy 127.595376 -339.16366) (xy 127.837692 -339.16366) (xy 127.837692 -339.103208) (xy 127.595376 -339.103208)
			)
		)
	)
	(zone
		(layer "F.Cu")
		(hatch none 0.5)
		(connect_pads
			(clearance 0)
		)
		(min_thickness 0.25)
		(keepout
			(tracks allowed)
			(vias allowed)
			(pads allowed)
			(copperpour allowed)
			(footprints allowed)
		)
		(placement
			(enabled no)
			(sheetname "")
		)
		(fill
			(thermal_gap 0.5)
			(thermal_bridge_width 0.5)
			(island_removal_mode 0)
		)
		(polygon
			(pts
				(xy 172.66666 -14.34084) (xy 172.66666 -12.87018) (xy 174.27194 -12.87018) (xy 174.27194 -14.34084)
			)
		)
	)
	(zone
		(layer "F.Cu")
		(hatch none 0.5)
		(connect_pads
			(clearance 0)
		)
		(min_thickness 0.25)
		(keepout
			(tracks allowed)
			(vias allowed)
			(pads allowed)
			(copperpour allowed)
			(footprints not_allowed)
		)
		(placement
			(enabled no)
			(sheetname "")
		)
		(fill
			(thermal_gap 0.5)
			(thermal_bridge_width 0.5)
			(island_removal_mode 0)
		)
		(polygon
			(pts
				(xy 75.924918 -363.21492) (xy 87.908638 -363.21492) (xy 87.908638 -348.836488) (xy 75.924918 -348.836488)
			)
		)
	)
	(zone
		(layer "F.Cu")
		(hatch none 0.5)
		(connect_pads
			(clearance 0)
		)
		(min_thickness 0.25)
		(keepout
			(tracks allowed)
			(vias allowed)
			(pads allowed)
			(copperpour allowed)
			(footprints not_allowed)
		)
		(placement
			(enabled no)
			(sheetname "")
		)
		(fill
			(thermal_gap 0.5)
			(thermal_bridge_width 0.5)
			(island_removal_mode 0)
		)
		(polygon
			(pts
				(arc
					(start 328.254868 -353.525074)
					(mid 329.854814 -351.925128)
					(end 331.45476 -353.525074)
				)
				(arc
					(start 331.45476 -353.525074)
					(mid 329.854814 -355.12502)
					(end 328.254868 -353.525074)
				)
			)
		)
	)
	(zone
		(layer "F.Cu")
		(hatch none 0.5)
		(connect_pads
			(clearance 0)
		)
		(min_thickness 0.25)
		(keepout
			(tracks allowed)
			(vias allowed)
			(pads allowed)
			(copperpour allowed)
			(footprints allowed)
		)
		(placement
			(enabled no)
			(sheetname "")
		)
		(fill
			(thermal_gap 0.5)
			(thermal_bridge_width 0.5)
			(island_removal_mode 0)
		)
		(polygon
			(pts
				(xy 11.11631 -285.516574) (xy 11.11631 -285.072836) (xy 13.441426 -285.072836) (xy 13.441426 -285.516574)
			)
		)
	)
	(zone
		(layer "F.Cu")
		(hatch none 0.5)
		(connect_pads
			(clearance 0)
		)
		(min_thickness 0.25)
		(keepout
			(tracks allowed)
			(vias allowed)
			(pads allowed)
			(copperpour allowed)
			(footprints not_allowed)
		)
		(placement
			(enabled no)
			(sheetname "")
		)
		(fill
			(thermal_gap 0.5)
			(thermal_bridge_width 0.5)
			(island_removal_mode 0)
		)
		(polygon
			(pts
				(arc
					(start 288.870644 -46.150022)
					(mid 281.437588 -52.650045)
					(end 274.004532 -46.150022)
				)
			)
		)
	)
	(zone
		(layer "F.Cu")
		(hatch none 0.5)
		(connect_pads
			(clearance 0)
		)
		(min_thickness 0.25)
		(keepout
			(tracks allowed)
			(vias allowed)
			(pads allowed)
			(copperpour allowed)
			(footprints allowed)
		)
		(placement
			(enabled no)
			(sheetname "")
		)
		(fill
			(thermal_gap 0.5)
			(thermal_bridge_width 0.5)
			(island_removal_mode 0)
		)
		(polygon
			(pts
				(xy 74.789284 -144.152366) (xy 74.789284 -143.629126) (xy 75.751944 -143.629126) (xy 75.751944 -144.152366)
				(xy 75.751944 -144.16405) (xy 74.789284 -144.16405)
			)
		)
	)
	(zone
		(layer "F.Cu")
		(hatch none 0.5)
		(connect_pads
			(clearance 0)
		)
		(min_thickness 0.25)
		(keepout
			(tracks allowed)
			(vias allowed)
			(pads allowed)
			(copperpour allowed)
			(footprints allowed)
		)
		(placement
			(enabled no)
			(sheetname "")
		)
		(fill
			(thermal_gap 0.5)
			(thermal_bridge_width 0.5)
			(island_removal_mode 0)
		)
		(polygon
			(pts
				(xy 197.553834 -235.256832) (xy 195.521834 -235.256832) (xy 195.521834 -235.254546) (xy 195.343018 -235.254546)
				(xy 195.343018 -235.01731) (xy 195.205096 -235.01731) (xy 195.161916 -234.97413) (xy 195.161916 -234.841288)
				(xy 195.161916 -234.53725) (xy 195.23456 -234.464606) (xy 197.774814 -234.464606) (xy 197.916038 -234.60583)
				(xy 197.916038 -234.802934) (xy 197.834504 -234.884468) (xy 197.834504 -235.256832) (xy 197.736968 -235.256832)
				(xy 197.689978 -235.256832)
			)
		)
	)
	(zone
		(layer "F.Cu")
		(hatch none 0.5)
		(connect_pads
			(clearance 0)
		)
		(min_thickness 0.25)
		(keepout
			(tracks allowed)
			(vias allowed)
			(pads allowed)
			(copperpour allowed)
			(footprints allowed)
		)
		(placement
			(enabled no)
			(sheetname "")
		)
		(fill
			(thermal_gap 0.5)
			(thermal_bridge_width 0.5)
			(island_removal_mode 0)
		)
		(polygon
			(pts
				(xy 415.880042 -159.54756) (xy 415.880042 -163.08324) (xy 413.797242 -163.08324) (xy 413.797242 -159.54756)
			)
		)
	)
	(zone
		(layer "F.Cu")
		(hatch none 0.5)
		(connect_pads
			(clearance 0)
		)
		(min_thickness 0.25)
		(keepout
			(tracks allowed)
			(vias allowed)
			(pads allowed)
			(copperpour allowed)
			(footprints allowed)
		)
		(placement
			(enabled no)
			(sheetname "")
		)
		(fill
			(thermal_gap 0.5)
			(thermal_bridge_width 0.5)
			(island_removal_mode 0)
		)
		(polygon
			(pts
				(xy 176.979326 -238.426244) (xy 179.011326 -238.426244) (xy 179.011326 -238.654844) (xy 176.979326 -238.654844)
				(xy 176.848008 -238.654844) (xy 176.8221 -238.654844) (xy 176.8221 -238.426244) (xy 176.848008 -238.426244)
			)
		)
	)
	(zone
		(layer "F.Cu")
		(hatch none 0.5)
		(connect_pads
			(clearance 0)
		)
		(min_thickness 0.25)
		(keepout
			(tracks allowed)
			(vias allowed)
			(pads allowed)
			(copperpour allowed)
			(footprints allowed)
		)
		(placement
			(enabled no)
			(sheetname "")
		)
		(fill
			(thermal_gap 0.5)
			(thermal_bridge_width 0.5)
			(island_removal_mode 0)
		)
		(polygon
			(pts
				(xy 304.319178 -268.922754) (xy 306.644294 -268.922754) (xy 306.644294 -269.366492) (xy 306.644294 -269.821914)
				(xy 304.161698 -269.821914) (xy 304.161698 -268.922754)
			)
		)
	)
	(zone
		(layer "F.Cu")
		(hatch none 0.5)
		(connect_pads
			(clearance 0)
		)
		(min_thickness 0.25)
		(keepout
			(tracks allowed)
			(vias allowed)
			(pads allowed)
			(copperpour allowed)
			(footprints not_allowed)
		)
		(placement
			(enabled no)
			(sheetname "")
		)
		(fill
			(thermal_gap 0.5)
			(thermal_bridge_width 0.5)
			(island_removal_mode 0)
		)
		(polygon
			(pts
				(xy 156.813504 -328.521822) (xy 151.363426 -328.521822) (xy 151.363426 -347.521784) (xy 223.169988 -347.521784)
				(xy 223.169988 -344.084656) (xy 217.670126 -344.084656) (xy 217.670126 -331.091794) (xy 156.813504 -331.091794)
			)
		)
	)
	(zone
		(layer "F.Cu")
		(hatch none 0.5)
		(connect_pads
			(clearance 0)
		)
		(min_thickness 0.25)
		(keepout
			(tracks allowed)
			(vias allowed)
			(pads allowed)
			(copperpour allowed)
			(footprints allowed)
		)
		(placement
			(enabled no)
			(sheetname "")
		)
		(fill
			(thermal_gap 0.5)
			(thermal_bridge_width 0.5)
			(island_removal_mode 0)
		)
		(polygon
			(pts
				(xy 157.791658 -282.005024) (xy 157.791658 -281.776424) (xy 159.823658 -281.776424) (xy 159.823658 -282.005024)
			)
		)
	)
	(zone
		(layer "F.Cu")
		(hatch none 0.5)
		(connect_pads
			(clearance 0)
		)
		(min_thickness 0.25)
		(keepout
			(tracks allowed)
			(vias allowed)
			(pads allowed)
			(copperpour allowed)
			(footprints not_allowed)
		)
		(placement
			(enabled no)
			(sheetname "")
		)
		(fill
			(thermal_gap 0.5)
			(thermal_bridge_width 0.5)
			(island_removal_mode 0)
		)
		(polygon
			(pts
				(xy 120.34012 -262.115046) (xy 120.34012 -236.514894) (xy 115.739926 -236.514894) (xy 115.739926 -262.115046)
			)
		)
	)
	(zone
		(layer "F.Cu")
		(hatch none 0.5)
		(connect_pads
			(clearance 0)
		)
		(min_thickness 0.25)
		(keepout
			(tracks allowed)
			(vias allowed)
			(pads allowed)
			(copperpour allowed)
			(footprints allowed)
		)
		(placement
			(enabled no)
			(sheetname "")
		)
		(fill
			(thermal_gap 0.5)
			(thermal_bridge_width 0.5)
			(island_removal_mode 0)
		)
		(polygon
			(pts
				(xy 176.979326 -284.556962) (xy 179.011326 -284.556962) (xy 179.011326 -284.328362) (xy 176.979326 -284.328362)
				(xy 176.848008 -284.328362) (xy 176.8221 -284.328362) (xy 176.8221 -284.556962) (xy 176.848008 -284.556962)
			)
		)
	)
	(zone
		(layer "F.Cu")
		(hatch none 0.5)
		(connect_pads
			(clearance 0)
		)
		(min_thickness 0.25)
		(keepout
			(tracks allowed)
			(vias allowed)
			(pads allowed)
			(copperpour allowed)
			(footprints allowed)
		)
		(placement
			(enabled no)
			(sheetname "")
		)
		(fill
			(thermal_gap 0.5)
			(thermal_bridge_width 0.5)
			(island_removal_mode 0)
		)
		(polygon
			(pts
				(xy 259.056378 -297.416474) (xy 259.056378 -296.972736) (xy 261.381494 -296.972736) (xy 261.381494 -297.416474)
			)
		)
	)
	(zone
		(layer "F.Cu")
		(hatch none 0.5)
		(connect_pads
			(clearance 0)
		)
		(min_thickness 0.25)
		(keepout
			(tracks allowed)
			(vias allowed)
			(pads allowed)
			(copperpour allowed)
			(footprints allowed)
		)
		(placement
			(enabled no)
			(sheetname "")
		)
		(fill
			(thermal_gap 0.5)
			(thermal_bridge_width 0.5)
			(island_removal_mode 0)
		)
		(polygon
			(pts
				(xy 8.6741 -100.162868) (xy 8.6741 -97.968308) (xy 12.065 -97.968308) (xy 12.065 -100.162868)
			)
		)
	)
	(zone
		(layer "F.Cu")
		(hatch none 0.5)
		(connect_pads
			(clearance 0)
		)
		(min_thickness 0.25)
		(keepout
			(tracks allowed)
			(vias allowed)
			(pads allowed)
			(copperpour allowed)
			(footprints allowed)
		)
		(placement
			(enabled no)
			(sheetname "")
		)
		(fill
			(thermal_gap 0.5)
			(thermal_bridge_width 0.5)
			(island_removal_mode 0)
		)
		(polygon
			(pts
				(xy 383.218944 -404.802594) (xy 383.218944 -399.959576) (xy 385.10337 -399.959576) (xy 385.10337 -404.802594)
			)
		)
	)
	(zone
		(layer "F.Cu")
		(hatch none 0.5)
		(connect_pads
			(clearance 0)
		)
		(min_thickness 0.25)
		(keepout
			(tracks allowed)
			(vias allowed)
			(pads allowed)
			(copperpour allowed)
			(footprints allowed)
		)
		(placement
			(enabled no)
			(sheetname "")
		)
		(fill
			(thermal_gap 0.5)
			(thermal_bridge_width 0.5)
			(island_removal_mode 0)
		)
		(polygon
			(pts
				(xy 424.919394 -293.906956) (xy 426.951394 -293.906956) (xy 426.951394 -293.678356) (xy 424.919394 -293.678356)
				(xy 424.788076 -293.678356) (xy 424.762168 -293.678356) (xy 424.762168 -293.906956) (xy 424.788076 -293.906956)
			)
		)
	)
	(zone
		(layer "F.Cu")
		(hatch none 0.5)
		(connect_pads
			(clearance 0)
		)
		(min_thickness 0.25)
		(keepout
			(tracks allowed)
			(vias allowed)
			(pads allowed)
			(copperpour allowed)
			(footprints allowed)
		)
		(placement
			(enabled no)
			(sheetname "")
		)
		(fill
			(thermal_gap 0.5)
			(thermal_bridge_width 0.5)
			(island_removal_mode 0)
		)
		(polygon
			(pts
				(xy 17.76984 -9.134348) (xy 17.76984 -6.264148) (xy 33.19272 -6.264148) (xy 33.19272 -9.134348)
			)
		)
	)
	(zone
		(layer "F.Cu")
		(hatch none 0.5)
		(connect_pads
			(clearance 0)
		)
		(min_thickness 0.25)
		(keepout
			(tracks allowed)
			(vias allowed)
			(pads allowed)
			(copperpour allowed)
			(footprints allowed)
		)
		(placement
			(enabled no)
			(sheetname "")
		)
		(fill
			(thermal_gap 0.5)
			(thermal_bridge_width 0.5)
			(island_removal_mode 0)
		)
		(polygon
			(pts
				(xy 409.831794 -222.505016) (xy 409.831794 -222.276416) (xy 411.863794 -222.276416) (xy 411.863794 -222.505016)
			)
		)
	)
	(zone
		(layer "F.Cu")
		(hatch none 0.5)
		(connect_pads
			(clearance 0)
		)
		(min_thickness 0.25)
		(keepout
			(tracks allowed)
			(vias allowed)
			(pads allowed)
			(copperpour allowed)
			(footprints allowed)
		)
		(placement
			(enabled no)
			(sheetname "")
		)
		(fill
			(thermal_gap 0.5)
			(thermal_bridge_width 0.5)
			(island_removal_mode 0)
		)
		(polygon
			(pts
				(xy 44.735242 -211.566506) (xy 44.735242 -211.122768) (xy 47.060358 -211.122768) (xy 47.060358 -211.566506)
			)
		)
	)
	(zone
		(layer "F.Cu")
		(hatch none 0.5)
		(connect_pads
			(clearance 0)
		)
		(min_thickness 0.25)
		(keepout
			(tracks allowed)
			(vias allowed)
			(pads allowed)
			(copperpour allowed)
			(footprints allowed)
		)
		(placement
			(enabled no)
			(sheetname "")
		)
		(fill
			(thermal_gap 0.5)
			(thermal_bridge_width 0.5)
			(island_removal_mode 0)
		)
		(polygon
			(pts
				(xy 133.07314 -215.247728) (xy 133.36016 -215.247728) (xy 133.39064 -215.217248) (xy 133.39064 -214.589868)
				(xy 133.30428 -214.503508) (xy 133.11632 -214.503508) (xy 133.04266 -214.577168) (xy 133.04266 -215.217248)
			)
		)
	)
	(zone
		(layer "F.Cu")
		(hatch none 0.5)
		(connect_pads
			(clearance 0)
		)
		(min_thickness 0.25)
		(keepout
			(tracks allowed)
			(vias allowed)
			(pads allowed)
			(copperpour allowed)
			(footprints allowed)
		)
		(placement
			(enabled no)
			(sheetname "")
		)
		(fill
			(thermal_gap 0.5)
			(thermal_bridge_width 0.5)
			(island_removal_mode 0)
		)
		(polygon
			(pts
				(xy 207.154526 -228.456998) (xy 209.186526 -228.456998) (xy 209.186526 -228.228398) (xy 207.154526 -228.228398)
				(xy 207.023208 -228.228398) (xy 206.9973 -228.228398) (xy 206.9973 -228.456998) (xy 207.023208 -228.456998)
			)
		)
	)
	(zone
		(layer "F.Cu")
		(hatch none 0.5)
		(connect_pads
			(clearance 0)
		)
		(min_thickness 0.25)
		(keepout
			(tracks allowed)
			(vias allowed)
			(pads allowed)
			(copperpour allowed)
			(footprints not_allowed)
		)
		(placement
			(enabled no)
			(sheetname "")
		)
		(fill
			(thermal_gap 0.5)
			(thermal_bridge_width 0.5)
			(island_removal_mode 0)
		)
		(polygon
			(pts
				(arc
					(start 62.782958 -45.449998)
					(mid 61.183012 -47.049944)
					(end 62.782958 -48.64989)
				)
				(arc
					(start 64.382904 -48.64989)
					(mid 65.98285 -47.049944)
					(end 64.382904 -45.449998)
				)
			)
		)
	)
	(zone
		(layer "F.Cu")
		(hatch none 0.5)
		(connect_pads
			(clearance 0)
		)
		(min_thickness 0.25)
		(keepout
			(tracks allowed)
			(vias allowed)
			(pads allowed)
			(copperpour allowed)
			(footprints allowed)
		)
		(placement
			(enabled no)
			(sheetname "")
		)
		(fill
			(thermal_gap 0.5)
			(thermal_bridge_width 0.5)
			(island_removal_mode 0)
		)
		(polygon
			(pts
				(xy 259.056378 -247.26646) (xy 259.056378 -246.822722) (xy 261.381494 -246.822722) (xy 261.381494 -247.26646)
			)
		)
	)
	(zone
		(layer "F.Cu")
		(hatch none 0.5)
		(connect_pads
			(clearance 0)
		)
		(min_thickness 0.25)
		(keepout
			(tracks allowed)
			(vias allowed)
			(pads allowed)
			(copperpour allowed)
			(footprints allowed)
		)
		(placement
			(enabled no)
			(sheetname "")
		)
		(fill
			(thermal_gap 0.5)
			(thermal_bridge_width 0.5)
			(island_removal_mode 0)
		)
		(polygon
			(pts
				(xy 440.006994 -274.976336) (xy 442.038994 -274.976336) (xy 442.038994 -274.978622) (xy 442.21781 -274.978622)
				(xy 442.21781 -275.215858) (xy 442.398912 -275.39696) (xy 442.414406 -275.412454) (xy 442.414406 -275.60143)
				(xy 442.398912 -275.616924) (xy 442.287914 -275.727922) (xy 442.247274 -275.768562) (xy 439.786014 -275.768562)
				(xy 439.64479 -275.627338) (xy 439.64479 -275.430234) (xy 439.726324 -275.3487) (xy 439.785252 -275.289772)
				(xy 439.785252 -274.976336) (xy 439.82386 -274.976336) (xy 439.87085 -274.976336)
			)
		)
	)
	(zone
		(layer "F.Cu")
		(hatch none 0.5)
		(connect_pads
			(clearance 0)
		)
		(min_thickness 0.25)
		(keepout
			(tracks allowed)
			(vias allowed)
			(pads allowed)
			(copperpour allowed)
			(footprints allowed)
		)
		(placement
			(enabled no)
			(sheetname "")
		)
		(fill
			(thermal_gap 0.5)
			(thermal_bridge_width 0.5)
			(island_removal_mode 0)
		)
		(polygon
			(pts
				(xy 399.881344 -410.948886) (xy 399.881344 -406.105868) (xy 401.76577 -406.105868) (xy 401.76577 -410.948886)
			)
		)
	)
	(zone
		(layer "F.Cu")
		(hatch none 0.5)
		(connect_pads
			(clearance 0)
		)
		(min_thickness 0.25)
		(keepout
			(tracks allowed)
			(vias allowed)
			(pads allowed)
			(copperpour allowed)
			(footprints allowed)
		)
		(placement
			(enabled no)
			(sheetname "")
		)
		(fill
			(thermal_gap 0.5)
			(thermal_bridge_width 0.5)
			(island_removal_mode 0)
		)
		(polygon
			(pts
				(xy 405.731726 -216.554812) (xy 405.731726 -216.326212) (xy 407.763726 -216.326212) (xy 407.763726 -216.554812)
			)
		)
	)
	(zone
		(layer "F.Cu")
		(hatch none 0.5)
		(connect_pads
			(clearance 0)
		)
		(min_thickness 0.25)
		(keepout
			(tracks allowed)
			(vias allowed)
			(pads allowed)
			(copperpour allowed)
			(footprints allowed)
		)
		(placement
			(enabled no)
			(sheetname "")
		)
		(fill
			(thermal_gap 0.5)
			(thermal_bridge_width 0.5)
			(island_removal_mode 0)
		)
		(polygon
			(pts
				(xy 59.822842 -198.816468) (xy 59.822842 -198.37273) (xy 62.147958 -198.37273) (xy 62.147958 -198.816468)
			)
		)
	)
	(zone
		(layer "F.Cu")
		(hatch none 0.5)
		(connect_pads
			(clearance 0)
		)
		(min_thickness 0.25)
		(keepout
			(tracks allowed)
			(vias allowed)
			(pads allowed)
			(copperpour allowed)
			(footprints allowed)
		)
		(placement
			(enabled no)
			(sheetname "")
		)
		(fill
			(thermal_gap 0.5)
			(thermal_bridge_width 0.5)
			(island_removal_mode 0)
		)
		(polygon
			(pts
				(xy 140.438632 -342.787478) (xy 136.902952 -342.787478) (xy 136.902952 -340.704678) (xy 140.438632 -340.704678)
			)
		)
	)
	(zone
		(layer "F.Cu")
		(hatch none 0.5)
		(connect_pads
			(clearance 0)
		)
		(min_thickness 0.25)
		(keepout
			(tracks allowed)
			(vias allowed)
			(pads allowed)
			(copperpour allowed)
			(footprints allowed)
		)
		(placement
			(enabled no)
			(sheetname "")
		)
		(fill
			(thermal_gap 0.5)
			(thermal_bridge_width 0.5)
			(island_removal_mode 0)
		)
		(polygon
			(pts
				(xy 440.006994 -300.476412) (xy 442.038994 -300.476412) (xy 442.038994 -300.705012) (xy 440.006994 -300.705012)
				(xy 439.87085 -300.705012) (xy 439.82386 -300.705012) (xy 439.757312 -300.705012) (xy 439.757312 -300.476412)
				(xy 439.82386 -300.476412) (xy 439.87085 -300.476412)
			)
		)
	)
	(zone
		(layer "F.Cu")
		(hatch none 0.5)
		(connect_pads
			(clearance 0)
		)
		(min_thickness 0.25)
		(keepout
			(tracks allowed)
			(vias allowed)
			(pads allowed)
			(copperpour allowed)
			(footprints allowed)
		)
		(placement
			(enabled no)
			(sheetname "")
		)
		(fill
			(thermal_gap 0.5)
			(thermal_bridge_width 0.5)
			(island_removal_mode 0)
		)
		(polygon
			(pts
				(xy 336.86496 -215.257888) (xy 337.15198 -215.257888) (xy 337.18246 -215.227408) (xy 337.18246 -214.600028)
				(xy 337.0961 -214.513668) (xy 336.90814 -214.513668) (xy 336.83448 -214.587328) (xy 336.83448 -215.227408)
			)
		)
	)
	(zone
		(layer "F.Cu")
		(hatch none 0.5)
		(connect_pads
			(clearance 0)
		)
		(min_thickness 0.25)
		(keepout
			(tracks allowed)
			(vias allowed)
			(pads allowed)
			(copperpour allowed)
			(footprints allowed)
		)
		(placement
			(enabled no)
			(sheetname "")
		)
		(fill
			(thermal_gap 0.5)
			(thermal_bridge_width 0.5)
			(island_removal_mode 0)
		)
		(polygon
			(pts
				(xy 259.056378 -207.316578) (xy 259.056378 -206.87284) (xy 261.381494 -206.87284) (xy 261.381494 -207.316578)
			)
		)
	)
	(zone
		(layer "F.Cu")
		(hatch none 0.5)
		(connect_pads
			(clearance 0)
		)
		(min_thickness 0.25)
		(keepout
			(tracks allowed)
			(vias allowed)
			(pads allowed)
			(copperpour allowed)
			(footprints allowed)
		)
		(placement
			(enabled no)
			(sheetname "")
		)
		(fill
			(thermal_gap 0.5)
			(thermal_bridge_width 0.5)
			(island_removal_mode 0)
		)
		(polygon
			(pts
				(xy 180.423058 -316.004956) (xy 180.423058 -315.776356) (xy 182.455058 -315.776356) (xy 182.455058 -316.004956)
			)
		)
	)
	(zone
		(layer "F.Cu")
		(hatch none 0.5)
		(connect_pads
			(clearance 0)
		)
		(min_thickness 0.25)
		(keepout
			(tracks allowed)
			(vias allowed)
			(pads allowed)
			(copperpour allowed)
			(footprints allowed)
		)
		(placement
			(enabled no)
			(sheetname "")
		)
		(fill
			(thermal_gap 0.5)
			(thermal_bridge_width 0.5)
			(island_removal_mode 0)
		)
		(polygon
			(pts
				(xy 168.71442 -18.748248) (xy 168.71442 -16.549878) (xy 174.066708 -16.549878) (xy 174.066708 -18.748248)
			)
		)
	)
	(zone
		(layer "F.Cu")
		(hatch none 0.5)
		(connect_pads
			(clearance 0)
		)
		(min_thickness 0.25)
		(keepout
			(tracks allowed)
			(vias allowed)
			(pads allowed)
			(copperpour allowed)
			(footprints allowed)
		)
		(placement
			(enabled no)
			(sheetname "")
		)
		(fill
			(thermal_gap 0.5)
			(thermal_bridge_width 0.5)
			(island_removal_mode 0)
		)
		(polygon
			(pts
				(xy 87.65794 -289.049968) (xy 87.94496 -289.049968) (xy 87.97544 -289.019488) (xy 87.97544 -288.392108)
				(xy 87.88908 -288.305748) (xy 87.70112 -288.305748) (xy 87.62746 -288.379408) (xy 87.62746 -289.019488)
			)
		)
	)
	(zone
		(layer "F.Cu")
		(hatch none 0.5)
		(connect_pads
			(clearance 0)
		)
		(min_thickness 0.25)
		(keepout
			(tracks allowed)
			(vias allowed)
			(pads allowed)
			(copperpour allowed)
			(footprints allowed)
		)
		(placement
			(enabled no)
			(sheetname "")
		)
		(fill
			(thermal_gap 0.5)
			(thermal_bridge_width 0.5)
			(island_removal_mode 0)
		)
		(polygon
			(pts
				(xy 176.979326 -303.876202) (xy 179.011326 -303.876202) (xy 179.011326 -304.104802) (xy 176.979326 -304.104802)
				(xy 176.848008 -304.104802) (xy 176.8221 -304.104802) (xy 176.8221 -303.876202) (xy 176.848008 -303.876202)
			)
		)
	)
	(zone
		(layer "F.Cu")
		(hatch none 0.5)
		(connect_pads
			(clearance 0)
		)
		(min_thickness 0.25)
		(keepout
			(tracks allowed)
			(vias allowed)
			(pads allowed)
			(copperpour allowed)
			(footprints allowed)
		)
		(placement
			(enabled no)
			(sheetname "")
		)
		(fill
			(thermal_gap 0.5)
			(thermal_bridge_width 0.5)
			(island_removal_mode 0)
		)
		(polygon
			(pts
				(xy 311.91708 -221.766638) (xy 311.91708 -221.3229) (xy 314.15228 -221.3229) (xy 314.187078 -221.3229)
				(xy 314.187078 -221.766638) (xy 314.15228 -221.766638)
			)
		)
	)
	(zone
		(layer "F.Cu")
		(hatch none 0.5)
		(connect_pads
			(clearance 0)
		)
		(min_thickness 0.25)
		(keepout
			(tracks allowed)
			(vias allowed)
			(pads allowed)
			(copperpour allowed)
			(footprints allowed)
		)
		(placement
			(enabled no)
			(sheetname "")
		)
		(fill
			(thermal_gap 0.5)
			(thermal_bridge_width 0.5)
			(island_removal_mode 0)
		)
		(polygon
			(pts
				(xy 405.181562 -316.668404) (xy 463.851244 -316.668404) (xy 464.168236 -316.351412) (xy 464.168236 -258.60629)
				(xy 463.762852 -258.200906) (xy 405.23414 -258.200906) (xy 405.128476 -258.30657) (xy 405.128476 -270.57477)
				(xy 404.931626 -270.77162) (xy 404.931626 -271.801336) (xy 404.931626 -273.100038) (xy 405.128476 -273.296888)
				(xy 405.128476 -274.434046) (xy 404.803102 -274.75942) (xy 404.803102 -278.880824) (xy 405.128476 -279.206198)
				(xy 405.128476 -281.422602) (xy 404.639526 -281.911552) (xy 404.537926 -282.013152) (xy 404.537926 -283.270452)
				(xy 404.639526 -283.372052) (xy 405.128476 -283.861002) (xy 405.128476 -316.615318)
			)
		)
	)
	(zone
		(layer "F.Cu")
		(hatch none 0.5)
		(connect_pads
			(clearance 0)
		)
		(min_thickness 0.25)
		(keepout
			(tracks allowed)
			(vias allowed)
			(pads allowed)
			(copperpour allowed)
			(footprints allowed)
		)
		(placement
			(enabled no)
			(sheetname "")
		)
		(fill
			(thermal_gap 0.5)
			(thermal_bridge_width 0.5)
			(island_removal_mode 0)
		)
		(polygon
			(pts
				(xy 63.900812 -219.216478) (xy 63.900812 -218.77274) (xy 66.237612 -218.77274) (xy 66.237612 -219.216478)
			)
		)
	)
	(zone
		(layer "F.Cu")
		(hatch none 0.5)
		(connect_pads
			(clearance 0)
		)
		(min_thickness 0.25)
		(keepout
			(tracks allowed)
			(vias allowed)
			(pads allowed)
			(copperpour allowed)
			(footprints allowed)
		)
		(placement
			(enabled no)
			(sheetname "")
		)
		(fill
			(thermal_gap 0.5)
			(thermal_bridge_width 0.5)
			(island_removal_mode 0)
		)
		(polygon
			(pts
				(xy 277.58771 -264.266426) (xy 277.58771 -263.822688) (xy 279.912826 -263.822688) (xy 279.912826 -264.266426)
			)
		)
	)
	(zone
		(layer "F.Cu")
		(hatch none 0.5)
		(connect_pads
			(clearance 0)
		)
		(min_thickness 0.25)
		(keepout
			(tracks allowed)
			(vias allowed)
			(pads allowed)
			(copperpour allowed)
			(footprints allowed)
		)
		(placement
			(enabled no)
			(sheetname "")
		)
		(fill
			(thermal_gap 0.5)
			(thermal_bridge_width 0.5)
			(island_removal_mode 0)
		)
		(polygon
			(pts
				(xy 167.378634 -270.95704) (xy 165.346634 -270.95704) (xy 165.346634 -270.954754) (xy 165.167818 -270.954754)
				(xy 165.167818 -270.717518) (xy 165.029896 -270.717518) (xy 164.986716 -270.674338) (xy 164.986716 -270.541496)
				(xy 164.986716 -270.237458) (xy 165.05936 -270.164814) (xy 167.599614 -270.164814) (xy 167.740838 -270.306038)
				(xy 167.740838 -270.503142) (xy 167.659304 -270.584676) (xy 167.659304 -270.95704) (xy 167.561768 -270.95704)
				(xy 167.514778 -270.95704)
			)
		)
	)
	(zone
		(layer "F.Cu")
		(hatch none 0.5)
		(connect_pads
			(clearance 0)
		)
		(min_thickness 0.25)
		(keepout
			(tracks allowed)
			(vias allowed)
			(pads allowed)
			(copperpour allowed)
			(footprints allowed)
		)
		(placement
			(enabled no)
			(sheetname "")
		)
		(fill
			(thermal_gap 0.5)
			(thermal_bridge_width 0.5)
			(island_removal_mode 0)
		)
		(polygon
			(pts
				(xy 307.76291 -211.566506) (xy 307.76291 -211.122768) (xy 310.088026 -211.122768) (xy 310.088026 -211.566506)
			)
		)
	)
	(zone
		(layer "F.Cu")
		(hatch none 0.5)
		(connect_pads
			(clearance 0)
		)
		(min_thickness 0.25)
		(keepout
			(tracks allowed)
			(vias allowed)
			(pads allowed)
			(copperpour allowed)
			(footprints allowed)
		)
		(placement
			(enabled no)
			(sheetname "")
		)
		(fill
			(thermal_gap 0.5)
			(thermal_bridge_width 0.5)
			(island_removal_mode 0)
		)
		(polygon
			(pts
				(xy 385.84632 -284.963108) (xy 386.13334 -284.963108) (xy 386.16382 -284.932628) (xy 386.16382 -284.305248)
				(xy 386.07746 -284.218888) (xy 385.8895 -284.218888) (xy 385.81584 -284.292548) (xy 385.81584 -284.932628)
			)
		)
	)
	(zone
		(layer "F.Cu")
		(hatch none 0.5)
		(connect_pads
			(clearance 0)
		)
		(min_thickness 0.25)
		(keepout
			(tracks allowed)
			(vias allowed)
			(pads allowed)
			(copperpour allowed)
			(footprints allowed)
		)
		(placement
			(enabled no)
			(sheetname "")
		)
		(fill
			(thermal_gap 0.5)
			(thermal_bridge_width 0.5)
			(island_removal_mode 0)
		)
		(polygon
			(pts
				(xy 311.91708 -310.166512) (xy 311.91708 -309.722774) (xy 314.12688 -309.722774) (xy 314.12688 -310.166512)
			)
		)
	)
	(zone
		(layer "F.Cu")
		(hatch none 0.5)
		(connect_pads
			(clearance 0)
		)
		(min_thickness 0.25)
		(keepout
			(tracks not_allowed)
			(vias allowed)
			(pads allowed)
			(copperpour not_allowed)
			(footprints allowed)
		)
		(placement
			(enabled no)
			(sheetname "")
		)
		(fill
			(thermal_gap 0.5)
			(thermal_bridge_width 0.5)
			(island_removal_mode 0)
		)
		(polygon
			(pts
				(xy 127.595376 -339.670644) (xy 131.52628 -339.670644) (xy 131.52628 -339.574632) (xy 131.43738 -339.485732)
				(xy 129.98323 -339.485732) (xy 129.98323 -337.326732) (xy 132.139944 -337.326732) (xy 132.139944 -337.07705)
				(xy 129.82448 -337.07705) (xy 129.82448 -337.401408) (xy 129.691892 -337.401408) (xy 129.691892 -339.430106)
				(xy 127.837692 -339.430106) (xy 127.837692 -339.18906) (xy 127.595376 -339.18906)
			)
		)
	)
	(zone
		(layer "F.Cu")
		(hatch none 0.5)
		(connect_pads
			(clearance 0)
		)
		(min_thickness 0.25)
		(keepout
			(tracks allowed)
			(vias allowed)
			(pads allowed)
			(copperpour allowed)
			(footprints allowed)
		)
		(placement
			(enabled no)
			(sheetname "")
		)
		(fill
			(thermal_gap 0.5)
			(thermal_bridge_width 0.5)
			(island_removal_mode 0)
		)
		(polygon
			(pts
				(xy 56.37911 -300.816518) (xy 56.37911 -300.37278) (xy 58.704226 -300.37278) (xy 58.704226 -300.816518)
			)
		)
	)
	(zone
		(layer "F.Cu")
		(hatch none 0.5)
		(connect_pads
			(clearance 0)
		)
		(min_thickness 0.25)
		(keepout
			(tracks allowed)
			(vias allowed)
			(pads allowed)
			(copperpour allowed)
			(footprints allowed)
		)
		(placement
			(enabled no)
			(sheetname "")
		)
		(fill
			(thermal_gap 0.5)
			(thermal_bridge_width 0.5)
			(island_removal_mode 0)
		)
		(polygon
			(pts
				(xy 304.319178 -249.81662) (xy 304.319178 -249.372882) (xy 306.644294 -249.372882) (xy 306.644294 -249.81662)
			)
		)
	)
	(zone
		(layer "F.Cu")
		(hatch none 0.5)
		(connect_pads
			(clearance 0)
		)
		(min_thickness 0.25)
		(keepout
			(tracks allowed)
			(vias allowed)
			(pads allowed)
			(copperpour allowed)
			(footprints allowed)
		)
		(placement
			(enabled no)
			(sheetname "")
		)
		(fill
			(thermal_gap 0.5)
			(thermal_bridge_width 0.5)
			(island_removal_mode 0)
		)
		(polygon
			(pts
				(xy 165.335458 -202.105006) (xy 165.335458 -201.876406) (xy 167.367458 -201.876406) (xy 167.367458 -202.105006)
			)
		)
	)
	(zone
		(layer "F.Cu")
		(hatch none 0.5)
		(connect_pads
			(clearance 0)
		)
		(min_thickness 0.25)
		(keepout
			(tracks allowed)
			(vias allowed)
			(pads allowed)
			(copperpour allowed)
			(footprints allowed)
		)
		(placement
			(enabled no)
			(sheetname "")
		)
		(fill
			(thermal_gap 0.5)
			(thermal_bridge_width 0.5)
			(island_removal_mode 0)
		)
		(polygon
			(pts
				(xy 455.094594 -314.076334) (xy 457.126594 -314.076334) (xy 457.126594 -314.304934) (xy 455.094594 -314.304934)
				(xy 454.95845 -314.304934) (xy 454.91146 -314.304934) (xy 454.91146 -314.076334) (xy 454.95845 -314.076334)
			)
		)
	)
	(zone
		(layer "F.Cu")
		(hatch none 0.5)
		(connect_pads
			(clearance 0)
		)
		(min_thickness 0.25)
		(keepout
			(tracks not_allowed)
			(vias allowed)
			(pads allowed)
			(copperpour not_allowed)
			(footprints allowed)
		)
		(placement
			(enabled no)
			(sheetname "")
		)
		(fill
			(thermal_gap 0.5)
			(thermal_bridge_width 0.5)
			(island_removal_mode 0)
		)
		(polygon
			(pts
				(xy 49.208944 -355.135688) (xy 49.45126 -355.135688) (xy 49.45126 -354.396548) (xy 49.208944 -354.396548)
			)
		)
	)
	(zone
		(layer "F.Cu")
		(hatch none 0.5)
		(connect_pads
			(clearance 0)
		)
		(min_thickness 0.25)
		(keepout
			(tracks allowed)
			(vias allowed)
			(pads allowed)
			(copperpour allowed)
			(footprints allowed)
		)
		(placement
			(enabled no)
			(sheetname "")
		)
		(fill
			(thermal_gap 0.5)
			(thermal_bridge_width 0.5)
			(island_removal_mode 0)
		)
		(polygon
			(pts
				(xy 26.20391 -306.766468) (xy 26.20391 -306.32273) (xy 28.529026 -306.32273) (xy 28.529026 -306.766468)
			)
		)
	)
	(zone
		(layer "F.Cu")
		(hatch none 0.5)
		(connect_pads
			(clearance 0)
		)
		(min_thickness 0.25)
		(keepout
			(tracks allowed)
			(vias allowed)
			(pads allowed)
			(copperpour allowed)
			(footprints allowed)
		)
		(placement
			(enabled no)
			(sheetname "")
		)
		(fill
			(thermal_gap 0.5)
			(thermal_bridge_width 0.5)
			(island_removal_mode 0)
		)
		(polygon
			(pts
				(xy 409.831794 -295.604946) (xy 409.831794 -295.376346) (xy 411.863794 -295.376346) (xy 411.863794 -295.604946)
			)
		)
	)
	(zone
		(layer "F.Cu")
		(hatch none 0.5)
		(connect_pads
			(clearance 0)
		)
		(min_thickness 0.25)
		(keepout
			(tracks allowed)
			(vias allowed)
			(pads allowed)
			(copperpour allowed)
			(footprints allowed)
		)
		(placement
			(enabled no)
			(sheetname "")
		)
		(fill
			(thermal_gap 0.5)
			(thermal_bridge_width 0.5)
			(island_removal_mode 0)
		)
		(polygon
			(pts
				(xy 259.056378 -291.466524) (xy 259.056378 -291.022786) (xy 261.381494 -291.022786) (xy 261.381494 -291.466524)
			)
		)
	)
	(zone
		(layer "F.Cu")
		(hatch none 0.5)
		(connect_pads
			(clearance 0)
		)
		(min_thickness 0.25)
		(keepout
			(tracks allowed)
			(vias allowed)
			(pads allowed)
			(copperpour allowed)
			(footprints allowed)
		)
		(placement
			(enabled no)
			(sheetname "")
		)
		(fill
			(thermal_gap 0.5)
			(thermal_bridge_width 0.5)
			(island_removal_mode 0)
		)
		(polygon
			(pts
				(xy 289.231578 -304.216562) (xy 289.231578 -303.772824) (xy 291.556694 -303.772824) (xy 291.556694 -304.216562)
			)
		)
	)
	(zone
		(layer "F.Cu")
		(hatch none 0.5)
		(connect_pads
			(clearance 0)
		)
		(min_thickness 0.25)
		(keepout
			(tracks allowed)
			(vias allowed)
			(pads allowed)
			(copperpour allowed)
			(footprints not_allowed)
		)
		(placement
			(enabled no)
			(sheetname "")
		)
		(fill
			(thermal_gap 0.5)
			(thermal_bridge_width 0.5)
			(island_removal_mode 0)
		)
		(polygon
			(pts
				(xy 189.362588 -79.760826) (xy 189.362334 -82.761074) (xy 221.860872 -82.764376) (xy 221.861126 -79.764382)
			)
		)
	)
	(zone
		(layer "F.Cu")
		(hatch none 0.5)
		(connect_pads
			(clearance 0)
		)
		(min_thickness 0.25)
		(keepout
			(tracks allowed)
			(vias allowed)
			(pads allowed)
			(copperpour allowed)
			(footprints allowed)
		)
		(placement
			(enabled no)
			(sheetname "")
		)
		(fill
			(thermal_gap 0.5)
			(thermal_bridge_width 0.5)
			(island_removal_mode 0)
		)
		(polygon
			(pts
				(xy 207.154526 -222.276416) (xy 209.186526 -222.276416) (xy 209.186526 -222.505016) (xy 207.154526 -222.505016)
				(xy 207.018382 -222.505016) (xy 206.971392 -222.505016) (xy 206.971392 -222.276416) (xy 207.018382 -222.276416)
			)
		)
	)
	(zone
		(layer "F.Cu")
		(hatch none 0.5)
		(connect_pads
			(clearance 0)
		)
		(min_thickness 0.25)
		(keepout
			(tracks allowed)
			(vias allowed)
			(pads allowed)
			(copperpour allowed)
			(footprints allowed)
		)
		(placement
			(enabled no)
			(sheetname "")
		)
		(fill
			(thermal_gap 0.5)
			(thermal_bridge_width 0.5)
			(island_removal_mode 0)
		)
		(polygon
			(pts
				(xy 180.423058 -282.854908) (xy 180.423058 -282.626308) (xy 182.455058 -282.626308) (xy 182.455058 -282.854908)
			)
		)
	)
	(zone
		(layer "F.Cu")
		(hatch none 0.5)
		(connect_pads
			(clearance 0)
		)
		(min_thickness 0.25)
		(keepout
			(tracks allowed)
			(vias allowed)
			(pads allowed)
			(copperpour allowed)
			(footprints allowed)
		)
		(placement
			(enabled no)
			(sheetname "")
		)
		(fill
			(thermal_gap 0.5)
			(thermal_bridge_width 0.5)
			(island_removal_mode 0)
		)
		(polygon
			(pts
				(xy 161.891726 -248.004838) (xy 161.891726 -247.776238) (xy 163.923726 -247.776238) (xy 163.923726 -248.004838)
			)
		)
	)
	(zone
		(layer "F.Cu")
		(hatch none 0.5)
		(connect_pads
			(clearance 0)
		)
		(min_thickness 0.25)
		(keepout
			(tracks allowed)
			(vias allowed)
			(pads allowed)
			(copperpour allowed)
			(footprints allowed)
		)
		(placement
			(enabled no)
			(sheetname "")
		)
		(fill
			(thermal_gap 0.5)
			(thermal_bridge_width 0.5)
			(island_removal_mode 0)
		)
		(polygon
			(pts
				(xy 259.056378 -288.06648) (xy 259.056378 -287.622742) (xy 261.381494 -287.622742) (xy 261.381494 -288.06648)
			)
		)
	)
	(zone
		(layer "F.Cu")
		(hatch none 0.5)
		(connect_pads
			(clearance 0)
		)
		(min_thickness 0.25)
		(keepout
			(tracks allowed)
			(vias allowed)
			(pads allowed)
			(copperpour allowed)
			(footprints allowed)
		)
		(placement
			(enabled no)
			(sheetname "")
		)
		(fill
			(thermal_gap 0.5)
			(thermal_bridge_width 0.5)
			(island_removal_mode 0)
		)
		(polygon
			(pts
				(xy 14.828774 -103.53294) (xy 14.828774 -102.56774) (xy 17.023334 -102.56774) (xy 17.023334 -103.53294)
			)
		)
	)
	(zone
		(layer "F.Cu")
		(hatch none 0.5)
		(connect_pads
			(clearance 0)
		)
		(min_thickness 0.25)
		(keepout
			(tracks allowed)
			(vias allowed)
			(pads allowed)
			(copperpour allowed)
			(footprints allowed)
		)
		(placement
			(enabled no)
			(sheetname "")
		)
		(fill
			(thermal_gap 0.5)
			(thermal_bridge_width 0.5)
			(island_removal_mode 0)
		)
		(polygon
			(pts
				(xy 279.912826 -233.666538) (xy 277.58771 -233.666538) (xy 277.456646 -233.666538) (xy 277.456646 -232.683558)
				(xy 279.977342 -232.683558) (xy 279.977342 -233.666538)
			)
		)
	)
	(zone
		(layer "F.Cu")
		(hatch none 0.5)
		(connect_pads
			(clearance 0)
		)
		(min_thickness 0.25)
		(keepout
			(tracks allowed)
			(vias allowed)
			(pads allowed)
			(copperpour allowed)
			(footprints allowed)
		)
		(placement
			(enabled no)
			(sheetname "")
		)
		(fill
			(thermal_gap 0.5)
			(thermal_bridge_width 0.5)
			(island_removal_mode 0)
		)
		(polygon
			(pts
				(xy 277.58771 -202.216512) (xy 277.58771 -201.772774) (xy 279.912826 -201.772774) (xy 279.912826 -202.216512)
			)
		)
	)
	(zone
		(layer "F.Cu")
		(hatch none 0.5)
		(connect_pads
			(clearance 0)
		)
		(min_thickness 0.25)
		(keepout
			(tracks allowed)
			(vias allowed)
			(pads allowed)
			(copperpour allowed)
			(footprints allowed)
		)
		(placement
			(enabled no)
			(sheetname "")
		)
		(fill
			(thermal_gap 0.5)
			(thermal_bridge_width 0.5)
			(island_removal_mode 0)
		)
		(polygon
			(pts
				(xy 165.335458 -218.254834) (xy 165.335458 -218.026234) (xy 167.367458 -218.026234) (xy 167.367458 -218.254834)
			)
		)
	)
	(zone
		(layer "F.Cu")
		(hatch none 0.5)
		(connect_pads
			(clearance 0)
		)
		(min_thickness 0.25)
		(keepout
			(tracks allowed)
			(vias allowed)
			(pads allowed)
			(copperpour allowed)
			(footprints allowed)
		)
		(placement
			(enabled no)
			(sheetname "")
		)
		(fill
			(thermal_gap 0.5)
			(thermal_bridge_width 0.5)
			(island_removal_mode 0)
		)
		(polygon
			(pts
				(xy 279.912826 -277.016464) (xy 277.58771 -277.016464) (xy 277.460964 -277.016464) (xy 277.460964 -276.07514)
				(xy 279.985724 -276.07514) (xy 279.985724 -277.016464)
			)
		)
	)
	(zone
		(layer "F.Cu")
		(hatch none 0.5)
		(connect_pads
			(clearance 0)
		)
		(min_thickness 0.25)
		(keepout
			(tracks allowed)
			(vias allowed)
			(pads allowed)
			(copperpour allowed)
			(footprints allowed)
		)
		(placement
			(enabled no)
			(sheetname "")
		)
		(fill
			(thermal_gap 0.5)
			(thermal_bridge_width 0.5)
			(island_removal_mode 0)
		)
		(polygon
			(pts
				(xy 26.20391 -230.266494) (xy 26.20391 -229.822756) (xy 28.529026 -229.822756) (xy 28.529026 -230.266494)
			)
		)
	)
	(zone
		(layer "F.Cu")
		(hatch none 0.5)
		(connect_pads
			(clearance 0)
		)
		(min_thickness 0.25)
		(keepout
			(tracks not_allowed)
			(vias allowed)
			(pads allowed)
			(copperpour not_allowed)
			(footprints allowed)
		)
		(placement
			(enabled no)
			(sheetname "")
		)
		(fill
			(thermal_gap 0.5)
			(thermal_bridge_width 0.5)
			(island_removal_mode 0)
		)
		(polygon
			(pts
				(xy 367.374678 -334.018128) (xy 367.616994 -334.018128) (xy 367.616994 -333.962502) (xy 368.16284 -333.962502)
				(xy 368.16284 -333.669386) (xy 367.614708 -333.669386) (xy 367.614708 -333.448914) (xy 366.919002 -333.448914)
				(xy 366.919002 -333.575914) (xy 367.374678 -333.575914)
			)
		)
	)
	(zone
		(layer "F.Cu")
		(hatch none 0.5)
		(connect_pads
			(clearance 0)
		)
		(min_thickness 0.25)
		(keepout
			(tracks allowed)
			(vias allowed)
			(pads allowed)
			(copperpour allowed)
			(footprints allowed)
		)
		(placement
			(enabled no)
			(sheetname "")
		)
		(fill
			(thermal_gap 0.5)
			(thermal_bridge_width 0.5)
			(island_removal_mode 0)
		)
		(polygon
			(pts
				(xy 165.335458 -247.154954) (xy 165.335458 -246.926354) (xy 167.367458 -246.926354) (xy 167.367458 -247.154954)
			)
		)
	)
	(zone
		(layer "F.Cu")
		(hatch none 0.5)
		(connect_pads
			(clearance 0)
		)
		(min_thickness 0.25)
		(keepout
			(tracks allowed)
			(vias allowed)
			(pads allowed)
			(copperpour allowed)
			(footprints allowed)
		)
		(placement
			(enabled no)
			(sheetname "")
		)
		(fill
			(thermal_gap 0.5)
			(thermal_bridge_width 0.5)
			(island_removal_mode 0)
		)
		(polygon
			(pts
				(xy 292.67531 -268.516608) (xy 292.67531 -268.07287) (xy 295.000426 -268.07287) (xy 295.000426 -268.516608)
			)
		)
	)
	(zone
		(layer "F.Cu")
		(hatch none 0.5)
		(connect_pads
			(clearance 0)
		)
		(min_thickness 0.25)
		(keepout
			(tracks allowed)
			(vias allowed)
			(pads allowed)
			(copperpour allowed)
			(footprints allowed)
		)
		(placement
			(enabled no)
			(sheetname "")
		)
		(fill
			(thermal_gap 0.5)
			(thermal_bridge_width 0.5)
			(island_removal_mode 0)
		)
		(polygon
			(pts
				(xy 455.094594 -285.176214) (xy 457.126594 -285.176214) (xy 457.126594 -285.404814) (xy 455.094594 -285.404814)
				(xy 454.963276 -285.404814) (xy 454.937368 -285.404814) (xy 454.937368 -285.176214) (xy 454.963276 -285.176214)
			)
		)
	)
	(zone
		(layer "F.Cu")
		(hatch none 0.5)
		(connect_pads
			(clearance 0)
		)
		(min_thickness 0.25)
		(keepout
			(tracks allowed)
			(vias allowed)
			(pads allowed)
			(copperpour allowed)
			(footprints allowed)
		)
		(placement
			(enabled no)
			(sheetname "")
		)
		(fill
			(thermal_gap 0.5)
			(thermal_bridge_width 0.5)
			(island_removal_mode 0)
		)
		(polygon
			(pts
				(xy 458.538326 -280.305002) (xy 458.538326 -280.076402) (xy 460.570326 -280.076402) (xy 460.570326 -280.305002)
			)
		)
	)
	(zone
		(layer "F.Cu")
		(hatch none 0.5)
		(connect_pads
			(clearance 0)
		)
		(min_thickness 0.25)
		(keepout
			(tracks allowed)
			(vias allowed)
			(pads allowed)
			(copperpour allowed)
			(footprints allowed)
		)
		(placement
			(enabled no)
			(sheetname "")
		)
		(fill
			(thermal_gap 0.5)
			(thermal_bridge_width 0.5)
			(island_removal_mode 0)
		)
		(polygon
			(pts
				(xy 26.20391 -314.41644) (xy 26.20391 -313.972702) (xy 28.529026 -313.972702) (xy 28.529026 -314.41644)
			)
		)
	)
	(zone
		(layer "F.Cu")
		(hatch none 0.5)
		(connect_pads
			(clearance 0)
		)
		(min_thickness 0.25)
		(keepout
			(tracks allowed)
			(vias allowed)
			(pads allowed)
			(copperpour allowed)
			(footprints allowed)
		)
		(placement
			(enabled no)
			(sheetname "")
		)
		(fill
			(thermal_gap 0.5)
			(thermal_bridge_width 0.5)
			(island_removal_mode 0)
		)
		(polygon
			(pts
				(xy 195.510658 -299.00499) (xy 195.510658 -298.77639) (xy 197.542658 -298.77639) (xy 197.542658 -299.00499)
			)
		)
	)
	(zone
		(layer "F.Cu")
		(hatch none 0.5)
		(connect_pads
			(clearance 0)
		)
		(min_thickness 0.25)
		(keepout
			(tracks allowed)
			(vias allowed)
			(pads allowed)
			(copperpour allowed)
			(footprints allowed)
		)
		(placement
			(enabled no)
			(sheetname "")
		)
		(fill
			(thermal_gap 0.5)
			(thermal_bridge_width 0.5)
			(island_removal_mode 0)
		)
		(polygon
			(pts
				(xy 192.066926 -312.606944) (xy 194.098926 -312.606944) (xy 194.098926 -312.378344) (xy 192.066926 -312.378344)
				(xy 191.935608 -312.378344) (xy 191.9097 -312.378344) (xy 191.9097 -312.606944) (xy 191.935608 -312.606944)
			)
		)
	)
	(zone
		(layer "F.Cu")
		(hatch none 0.5)
		(connect_pads
			(clearance 0)
		)
		(min_thickness 0.25)
		(keepout
			(tracks allowed)
			(vias allowed)
			(pads allowed)
			(copperpour allowed)
			(footprints allowed)
		)
		(placement
			(enabled no)
			(sheetname "")
		)
		(fill
			(thermal_gap 0.5)
			(thermal_bridge_width 0.5)
			(island_removal_mode 0)
		)
		(polygon
			(pts
				(xy 44.735242 -308.46649) (xy 44.735242 -308.022752) (xy 47.060358 -308.022752) (xy 47.060358 -308.46649)
			)
		)
	)
	(zone
		(layer "F.Cu")
		(hatch none 0.5)
		(connect_pads
			(clearance 0)
		)
		(min_thickness 0.25)
		(keepout
			(tracks allowed)
			(vias allowed)
			(pads allowed)
			(copperpour allowed)
			(footprints allowed)
		)
		(placement
			(enabled no)
			(sheetname "")
		)
		(fill
			(thermal_gap 0.5)
			(thermal_bridge_width 0.5)
			(island_removal_mode 0)
		)
		(polygon
			(pts
				(xy 455.094594 -291.126418) (xy 457.126594 -291.126418) (xy 457.126594 -291.355018) (xy 455.094594 -291.355018)
				(xy 454.95845 -291.355018) (xy 454.91146 -291.355018) (xy 454.91146 -291.126418) (xy 454.95845 -291.126418)
			)
		)
	)
	(zone
		(layer "F.Cu")
		(hatch none 0.5)
		(connect_pads
			(clearance 0)
		)
		(min_thickness 0.25)
		(keepout
			(tracks allowed)
			(vias allowed)
			(pads allowed)
			(copperpour allowed)
			(footprints not_allowed)
		)
		(placement
			(enabled no)
			(sheetname "")
		)
		(fill
			(thermal_gap 0.5)
			(thermal_bridge_width 0.5)
			(island_removal_mode 0)
		)
		(polygon
			(pts
				(xy 351.94494 -237.00994) (xy 351.94494 -261.62) (xy 355.575108 -261.62) (xy 355.575108 -237.00994)
			)
		)
	)
	(zone
		(layer "F.Cu")
		(hatch none 0.5)
		(connect_pads
			(clearance 0)
		)
		(min_thickness 0.25)
		(keepout
			(tracks allowed)
			(vias allowed)
			(pads allowed)
			(copperpour allowed)
			(footprints allowed)
		)
		(placement
			(enabled no)
			(sheetname "")
		)
		(fill
			(thermal_gap 0.5)
			(thermal_bridge_width 0.5)
			(island_removal_mode 0)
		)
		(polygon
			(pts
				(xy 428.363126 -311.755028) (xy 428.363126 -311.526428) (xy 430.395126 -311.526428) (xy 430.395126 -311.755028)
			)
		)
	)
	(zone
		(layer "F.Cu")
		(hatch none 0.5)
		(connect_pads
			(clearance 0)
		)
		(min_thickness 0.25)
		(keepout
			(tracks allowed)
			(vias allowed)
			(pads allowed)
			(copperpour allowed)
			(footprints allowed)
		)
		(placement
			(enabled no)
			(sheetname "")
		)
		(fill
			(thermal_gap 0.5)
			(thermal_bridge_width 0.5)
			(island_removal_mode 0)
		)
		(polygon
			(pts
				(xy 405.731726 -266.704826) (xy 405.731726 -266.476226) (xy 407.763726 -266.476226) (xy 407.763726 -266.704826)
			)
		)
	)
	(zone
		(layer "F.Cu")
		(hatch none 0.5)
		(connect_pads
			(clearance 0)
		)
		(min_thickness 0.25)
		(keepout
			(tracks not_allowed)
			(vias allowed)
			(pads allowed)
			(copperpour not_allowed)
			(footprints allowed)
		)
		(placement
			(enabled no)
			(sheetname "")
		)
		(fill
			(thermal_gap 0.5)
			(thermal_bridge_width 0.5)
			(island_removal_mode 0)
		)
		(polygon
			(pts
				(arc
					(start 14.412214 -31.356554)
					(mid 16.603023 -31.283593)
					(end 16.530066 -29.092652)
				)
				(arc
					(start 15.361666 -27.99969)
					(mid 13.170721 -28.072779)
					(end 13.243814 -30.263592)
				)
			)
		)
	)
	(zone
		(layer "F.Cu")
		(hatch none 0.5)
		(connect_pads
			(clearance 0)
		)
		(min_thickness 0.25)
		(keepout
			(tracks allowed)
			(vias allowed)
			(pads allowed)
			(copperpour allowed)
			(footprints allowed)
		)
		(placement
			(enabled no)
			(sheetname "")
		)
		(fill
			(thermal_gap 0.5)
			(thermal_bridge_width 0.5)
			(island_removal_mode 0)
		)
		(polygon
			(pts
				(xy 274.144232 -229.416356) (xy 274.144232 -228.972618) (xy 276.469348 -228.972618) (xy 276.469348 -229.416356)
			)
		)
	)
	(zone
		(layer "F.Cu")
		(hatch none 0.5)
		(connect_pads
			(clearance 0)
		)
		(min_thickness 0.25)
		(keepout
			(tracks allowed)
			(vias allowed)
			(pads allowed)
			(copperpour allowed)
			(footprints allowed)
		)
		(placement
			(enabled no)
			(sheetname "")
		)
		(fill
			(thermal_gap 0.5)
			(thermal_bridge_width 0.5)
			(island_removal_mode 0)
		)
		(polygon
			(pts
				(xy 29.647642 -203.06665) (xy 29.647642 -202.622912) (xy 31.972758 -202.622912) (xy 31.972758 -203.06665)
			)
		)
	)
	(zone
		(layer "F.Cu")
		(hatch none 0.5)
		(connect_pads
			(clearance 0)
		)
		(min_thickness 0.25)
		(keepout
			(tracks allowed)
			(vias allowed)
			(pads allowed)
			(copperpour allowed)
			(footprints allowed)
		)
		(placement
			(enabled no)
			(sheetname "")
		)
		(fill
			(thermal_gap 0.5)
			(thermal_bridge_width 0.5)
			(island_removal_mode 0)
		)
		(polygon
			(pts
				(xy 462.38033 -319.243202) (xy 462.38033 -316.881002) (xy 464.99653 -316.881002) (xy 464.99653 -319.243202)
			)
		)
	)
	(zone
		(layer "F.Cu")
		(hatch none 0.5)
		(connect_pads
			(clearance 0)
		)
		(min_thickness 0.25)
		(keepout
			(tracks allowed)
			(vias allowed)
			(pads allowed)
			(copperpour allowed)
			(footprints allowed)
		)
		(placement
			(enabled no)
			(sheetname "")
		)
		(fill
			(thermal_gap 0.5)
			(thermal_bridge_width 0.5)
			(island_removal_mode 0)
		)
		(polygon
			(pts
				(xy 307.76291 -311.866534) (xy 307.76291 -311.422796) (xy 310.088026 -311.422796) (xy 310.088026 -311.866534)
			)
		)
	)
	(zone
		(layer "F.Cu")
		(hatch none 0.5)
		(connect_pads
			(clearance 0)
		)
		(min_thickness 0.25)
		(keepout
			(tracks allowed)
			(vias allowed)
			(pads allowed)
			(copperpour allowed)
			(footprints allowed)
		)
		(placement
			(enabled no)
			(sheetname "")
		)
		(fill
			(thermal_gap 0.5)
			(thermal_bridge_width 0.5)
			(island_removal_mode 0)
		)
		(polygon
			(pts
				(xy 195.510658 -208.90484) (xy 195.510658 -208.67624) (xy 197.542658 -208.67624) (xy 197.542658 -208.90484)
			)
		)
	)
	(zone
		(layer "F.Cu")
		(hatch none 0.5)
		(connect_pads
			(clearance 0)
		)
		(min_thickness 0.25)
		(keepout
			(tracks allowed)
			(vias allowed)
			(pads allowed)
			(copperpour allowed)
			(footprints allowed)
		)
		(placement
			(enabled no)
			(sheetname "")
		)
		(fill
			(thermal_gap 0.5)
			(thermal_bridge_width 0.5)
			(island_removal_mode 0)
		)
		(polygon
			(pts
				(xy 255.499616 -316.668658) (xy 311.197752 -316.668658) (xy 311.299352 -316.668658) (xy 314.554108 -316.668658)
				(xy 314.79744 -316.668658) (xy 314.917582 -316.548516) (xy 314.917582 -314.826904) (xy 314.917582 -309.818532)
				(xy 314.917582 -309.235348) (xy 314.48629 -308.804056) (xy 314.48629 -297.694096) (xy 314.699904 -297.480482)
				(xy 314.699904 -295.967912) (xy 314.48629 -295.754298) (xy 314.48629 -288.263076) (xy 314.555632 -288.193734)
				(xy 314.555632 -286.610298) (xy 314.555632 -285.095696) (xy 314.84062 -284.810708) (xy 314.84062 -281.283664)
				(xy 314.685172 -281.128216) (xy 314.555632 -280.998676) (xy 314.555632 -279.116536) (xy 314.761372 -278.910796)
				(xy 314.761372 -277.539196) (xy 314.555632 -277.333456) (xy 314.555632 -273.599656) (xy 314.860432 -273.294856)
				(xy 314.860432 -271.407636) (xy 314.555632 -271.102836) (xy 314.555632 -268.67993) (xy 315.071506 -268.164056)
				(xy 315.071506 -267.00607) (xy 314.555632 -266.490196) (xy 314.555632 -258.675886) (xy 314.48629 -258.606544)
				(xy 314.080906 -258.20116) (xy 255.552194 -258.20116) (xy 255.44653 -258.306824) (xy 255.44653 -316.615572)
			)
		)
	)
	(zone
		(layer "F.Cu")
		(hatch none 0.5)
		(connect_pads
			(clearance 0)
		)
		(min_thickness 0.25)
		(keepout
			(tracks allowed)
			(vias allowed)
			(pads allowed)
			(copperpour allowed)
			(footprints allowed)
		)
		(placement
			(enabled no)
			(sheetname "")
		)
		(fill
			(thermal_gap 0.5)
			(thermal_bridge_width 0.5)
			(island_removal_mode 0)
		)
		(polygon
			(pts
				(xy 311.91708 -309.316628) (xy 311.91708 -308.87289) (xy 314.15228 -308.87289) (xy 314.15228 -309.316628)
			)
		)
	)
	(zone
		(layer "F.Cu")
		(hatch none 0.5)
		(connect_pads
			(clearance 0)
		)
		(min_thickness 0.25)
		(keepout
			(tracks allowed)
			(vias allowed)
			(pads allowed)
			(copperpour allowed)
			(footprints allowed)
		)
		(placement
			(enabled no)
			(sheetname "")
		)
		(fill
			(thermal_gap 0.5)
			(thermal_bridge_width 0.5)
			(island_removal_mode 0)
		)
		(polygon
			(pts
				(xy 274.143978 -224.316544) (xy 274.143978 -223.872806) (xy 276.469094 -223.872806) (xy 276.469094 -224.316544)
			)
		)
	)
	(zone
		(layer "F.Cu")
		(hatch none 0.5)
		(connect_pads
			(clearance 0)
		)
		(min_thickness 0.25)
		(keepout
			(tracks allowed)
			(vias allowed)
			(pads allowed)
			(copperpour allowed)
			(footprints not_allowed)
		)
		(placement
			(enabled no)
			(sheetname "")
		)
		(fill
			(thermal_gap 0.5)
			(thermal_bridge_width 0.5)
			(island_removal_mode 0)
		)
		(polygon
			(pts
				(xy 288.396426 -139.291568) (xy 288.395664 -144.763236) (xy 431.395632 -144.763236) (xy 431.396394 -139.309856)
				(xy 452.394066 -139.308586) (xy 452.394066 -144.763236) (xy 467.300056 -144.763236) (xy 467.300056 -91.764358)
				(xy 250.001024 -91.764358) (xy 249.99569 -144.763236) (xy 267.395706 -144.763236) (xy 267.396214 -139.289282)
			)
		)
	)
	(zone
		(layer "F.Cu")
		(hatch none 0.5)
		(connect_pads
			(clearance 0)
		)
		(min_thickness 0.25)
		(keepout
			(tracks allowed)
			(vias allowed)
			(pads allowed)
			(copperpour allowed)
			(footprints allowed)
		)
		(placement
			(enabled no)
			(sheetname "")
		)
		(fill
			(thermal_gap 0.5)
			(thermal_bridge_width 0.5)
			(island_removal_mode 0)
		)
		(polygon
			(pts
				(xy 96.113092 -332.908402) (xy 94.296992 -332.908402) (xy 94.296992 -331.529182) (xy 96.113092 -331.529182)
			)
		)
	)
	(zone
		(layer "F.Cu")
		(hatch none 0.5)
		(connect_pads
			(clearance 0)
		)
		(min_thickness 0.25)
		(keepout
			(tracks allowed)
			(vias allowed)
			(pads allowed)
			(copperpour allowed)
			(footprints allowed)
		)
		(placement
			(enabled no)
			(sheetname "")
		)
		(fill
			(thermal_gap 0.5)
			(thermal_bridge_width 0.5)
			(island_removal_mode 0)
		)
		(polygon
			(pts
				(xy 458.538326 -272.65503) (xy 458.538326 -272.42643) (xy 460.570326 -272.42643) (xy 460.570326 -272.65503)
			)
		)
	)
	(zone
		(layer "F.Cu")
		(hatch none 0.5)
		(connect_pads
			(clearance 0)
		)
		(min_thickness 0.25)
		(keepout
			(tracks allowed)
			(vias allowed)
			(pads allowed)
			(copperpour allowed)
			(footprints allowed)
		)
		(placement
			(enabled no)
			(sheetname "")
		)
		(fill
			(thermal_gap 0.5)
			(thermal_bridge_width 0.5)
			(island_removal_mode 0)
		)
		(polygon
			(pts
				(xy 207.154526 -275.206968) (xy 209.186526 -275.206968) (xy 209.186526 -274.978368) (xy 207.154526 -274.978368)
				(xy 207.023208 -274.978368) (xy 206.9973 -274.978368) (xy 206.9973 -275.206968) (xy 207.023208 -275.206968)
			)
		)
	)
	(zone
		(layer "F.Cu")
		(hatch none 0.5)
		(connect_pads
			(clearance 0)
		)
		(min_thickness 0.25)
		(keepout
			(tracks not_allowed)
			(vias allowed)
			(pads allowed)
			(copperpour not_allowed)
			(footprints allowed)
		)
		(placement
			(enabled no)
			(sheetname "")
		)
		(fill
			(thermal_gap 0.5)
			(thermal_bridge_width 0.5)
			(island_removal_mode 0)
		)
		(polygon
			(pts
				(arc
					(start 80.014826 -251.76988)
					(mid 77.919834 -253.864872)
					(end 75.824842 -251.76988)
				)
				(arc
					(start 75.824842 -251.76988)
					(mid 77.919834 -249.674888)
					(end 80.014826 -251.76988)
				)
			)
		)
	)
	(zone
		(layer "F.Cu")
		(hatch none 0.5)
		(connect_pads
			(clearance 0)
		)
		(min_thickness 0.25)
		(keepout
			(tracks allowed)
			(vias allowed)
			(pads allowed)
			(copperpour allowed)
			(footprints allowed)
		)
		(placement
			(enabled no)
			(sheetname "")
		)
		(fill
			(thermal_gap 0.5)
			(thermal_bridge_width 0.5)
			(island_removal_mode 0)
		)
		(polygon
			(pts
				(xy 11.11631 -233.666538) (xy 11.11631 -233.2228) (xy 13.441426 -233.2228) (xy 13.441426 -233.666538)
			)
		)
	)
	(zone
		(layer "F.Cu")
		(hatch none 0.5)
		(connect_pads
			(clearance 0)
		)
		(min_thickness 0.25)
		(keepout
			(tracks allowed)
			(vias allowed)
			(pads allowed)
			(copperpour allowed)
			(footprints allowed)
		)
		(placement
			(enabled no)
			(sheetname "")
		)
		(fill
			(thermal_gap 0.5)
			(thermal_bridge_width 0.5)
			(island_removal_mode 0)
		)
		(polygon
			(pts
				(xy 161.891726 -225.67646) (xy 163.923726 -225.67646) (xy 163.923726 -225.90506) (xy 161.891726 -225.90506)
				(xy 161.755582 -225.90506) (xy 161.708592 -225.90506) (xy 161.708592 -225.67646) (xy 161.755582 -225.67646)
			)
		)
	)
	(zone
		(layer "F.Cu")
		(hatch none 0.5)
		(connect_pads
			(clearance 0)
		)
		(min_thickness 0.25)
		(keepout
			(tracks allowed)
			(vias allowed)
			(pads allowed)
			(copperpour allowed)
			(footprints allowed)
		)
		(placement
			(enabled no)
			(sheetname "")
		)
		(fill
			(thermal_gap 0.5)
			(thermal_bridge_width 0.5)
			(island_removal_mode 0)
		)
		(polygon
			(pts
				(xy 26.20391 -304.216562) (xy 26.20391 -303.772824) (xy 28.529026 -303.772824) (xy 28.529026 -304.216562)
			)
		)
	)
	(zone
		(layer "F.Cu")
		(hatch none 0.5)
		(connect_pads
			(clearance 0)
		)
		(min_thickness 0.25)
		(keepout
			(tracks allowed)
			(vias allowed)
			(pads allowed)
			(copperpour allowed)
			(footprints allowed)
		)
		(placement
			(enabled no)
			(sheetname "")
		)
		(fill
			(thermal_gap 0.5)
			(thermal_bridge_width 0.5)
			(island_removal_mode 0)
		)
		(polygon
			(pts
				(xy 192.066926 -294.526208) (xy 194.098926 -294.526208) (xy 194.098926 -294.754808) (xy 192.066926 -294.754808)
				(xy 191.935608 -294.754808) (xy 191.9097 -294.754808) (xy 191.9097 -294.526208) (xy 191.935608 -294.526208)
			)
		)
	)
	(zone
		(layer "F.Cu")
		(hatch none 0.5)
		(connect_pads
			(clearance 0)
		)
		(min_thickness 0.25)
		(keepout
			(tracks allowed)
			(vias allowed)
			(pads allowed)
			(copperpour allowed)
			(footprints allowed)
		)
		(placement
			(enabled no)
			(sheetname "")
		)
		(fill
			(thermal_gap 0.5)
			(thermal_bridge_width 0.5)
			(island_removal_mode 0)
		)
		(polygon
			(pts
				(xy 251.05868 -103.876348) (xy 251.05868 -101.742748) (xy 250.16968 -101.742748) (xy 249.70105 -101.274118)
				(xy 249.70105 -100.105718) (xy 248.72188 -99.126548) (xy 248.72188 -98.186748) (xy 250.93168 -95.976948)
				(xy 251.05868 -95.976948) (xy 251.05868 -95.494348) (xy 253.81204 -95.494348) (xy 253.81204 -94.275148)
				(xy 254.31242 -93.774768) (xy 254.3429 -93.744288) (xy 254.3429 -93.241368) (xy 254.63754 -92.946728)
				(xy 257.59918 -92.946728) (xy 258.42722 -93.774768) (xy 259.96646 -93.774768) (xy 260.21284 -94.021148)
				(xy 260.21284 -94.625668) (xy 259.6896 -95.148908) (xy 259.6896 -95.494348) (xy 260.22808 -95.494348)
				(xy 260.22808 -96.073468) (xy 260.2865 -96.015048) (xy 263.11606 -96.015048) (xy 263.2202 -96.119188)
				(xy 263.2202 -97.869248) (xy 262.21182 -98.877628) (xy 260.39318 -98.877628) (xy 260.22808 -99.042728)
				(xy 260.22808 -103.876348) (xy 259.74548 -103.876348) (xy 259.74548 -105.222548) (xy 258.80568 -106.162348)
				(xy 252.63348 -106.162348) (xy 251.05868 -104.587548)
			)
		)
	)
	(zone
		(layer "F.Cu")
		(hatch none 0.5)
		(connect_pads
			(clearance 0)
		)
		(min_thickness 0.25)
		(keepout
			(tracks allowed)
			(vias allowed)
			(pads allowed)
			(copperpour allowed)
			(footprints allowed)
		)
		(placement
			(enabled no)
			(sheetname "")
		)
		(fill
			(thermal_gap 0.5)
			(thermal_bridge_width 0.5)
			(island_removal_mode 0)
		)
		(polygon
			(pts
				(xy 409.831794 -278.37638) (xy 411.863794 -278.37638) (xy 411.863794 -278.378666) (xy 412.04261 -278.378666)
				(xy 412.04261 -278.615902) (xy 412.180532 -278.615902) (xy 412.223712 -278.659082) (xy 412.223712 -278.791924)
				(xy 412.223712 -279.095962) (xy 412.151068 -279.168606) (xy 409.610814 -279.168606) (xy 409.46959 -279.027382)
				(xy 409.46959 -278.830278) (xy 409.551124 -278.748744) (xy 409.551124 -278.37638) (xy 409.64866 -278.37638)
				(xy 409.69565 -278.37638)
			)
		)
	)
	(zone
		(layer "F.Cu")
		(hatch none 0.5)
		(connect_pads
			(clearance 0)
		)
		(min_thickness 0.25)
		(keepout
			(tracks allowed)
			(vias allowed)
			(pads allowed)
			(copperpour allowed)
			(footprints allowed)
		)
		(placement
			(enabled no)
			(sheetname "")
		)
		(fill
			(thermal_gap 0.5)
			(thermal_bridge_width 0.5)
			(island_removal_mode 0)
		)
		(polygon
			(pts
				(xy 458.538326 -236.954822) (xy 458.538326 -236.726222) (xy 460.570326 -236.726222) (xy 460.570326 -236.954822)
			)
		)
	)
	(zone
		(layer "F.Cu")
		(hatch none 0.5)
		(connect_pads
			(clearance 0)
		)
		(min_thickness 0.25)
		(keepout
			(tracks allowed)
			(vias allowed)
			(pads allowed)
			(copperpour allowed)
			(footprints allowed)
		)
		(placement
			(enabled no)
			(sheetname "")
		)
		(fill
			(thermal_gap 0.5)
			(thermal_bridge_width 0.5)
			(island_removal_mode 0)
		)
		(polygon
			(pts
				(xy 192.066926 -251.176282) (xy 194.098926 -251.176282) (xy 194.098926 -251.404882) (xy 192.066926 -251.404882)
				(xy 191.900302 -251.404882) (xy 191.900302 -251.176282)
			)
		)
	)
	(zone
		(layer "F.Cu")
		(hatch none 0.5)
		(connect_pads
			(clearance 0)
		)
		(min_thickness 0.25)
		(keepout
			(tracks allowed)
			(vias allowed)
			(pads allowed)
			(copperpour allowed)
			(footprints allowed)
		)
		(placement
			(enabled no)
			(sheetname "")
		)
		(fill
			(thermal_gap 0.5)
			(thermal_bridge_width 0.5)
			(island_removal_mode 0)
		)
		(polygon
			(pts
				(xy 195.510658 -218.254834) (xy 195.510658 -218.026234) (xy 197.542658 -218.026234) (xy 197.542658 -218.254834)
			)
		)
	)
	(zone
		(layer "F.Cu")
		(hatch none 0.5)
		(connect_pads
			(clearance 0)
		)
		(min_thickness 0.25)
		(keepout
			(tracks allowed)
			(vias allowed)
			(pads allowed)
			(copperpour allowed)
			(footprints allowed)
		)
		(placement
			(enabled no)
			(sheetname "")
		)
		(fill
			(thermal_gap 0.5)
			(thermal_bridge_width 0.5)
			(island_removal_mode 0)
		)
		(polygon
			(pts
				(xy 307.85308 -245.566438) (xy 307.85308 -245.1227) (xy 310.01208 -245.1227) (xy 310.01208 -245.566438)
			)
		)
	)
	(zone
		(layer "F.Cu")
		(hatch none 0.5)
		(connect_pads
			(clearance 0)
		)
		(min_thickness 0.25)
		(keepout
			(tracks allowed)
			(vias allowed)
			(pads allowed)
			(copperpour allowed)
			(footprints allowed)
		)
		(placement
			(enabled no)
			(sheetname "")
		)
		(fill
			(thermal_gap 0.5)
			(thermal_bridge_width 0.5)
			(island_removal_mode 0)
		)
		(polygon
			(pts
				(xy 120.594628 -332.908402) (xy 118.778528 -332.908402) (xy 118.778528 -331.529182) (xy 120.594628 -331.529182)
			)
		)
	)
	(zone
		(layer "F.Cu")
		(hatch none 0.5)
		(connect_pads
			(clearance 0)
		)
		(min_thickness 0.25)
		(keepout
			(tracks allowed)
			(vias allowed)
			(pads allowed)
			(copperpour allowed)
			(footprints allowed)
		)
		(placement
			(enabled no)
			(sheetname "")
		)
		(fill
			(thermal_gap 0.5)
			(thermal_bridge_width 0.5)
			(island_removal_mode 0)
		)
		(polygon
			(pts
				(xy 44.735242 -295.716452) (xy 44.735242 -295.272714) (xy 47.060358 -295.272714) (xy 47.060358 -295.716452)
			)
		)
	)
	(zone
		(layer "F.Cu")
		(hatch none 0.5)
		(connect_pads
			(clearance 0)
		)
		(min_thickness 0.25)
		(keepout
			(tracks allowed)
			(vias allowed)
			(pads allowed)
			(copperpour allowed)
			(footprints allowed)
		)
		(placement
			(enabled no)
			(sheetname "")
		)
		(fill
			(thermal_gap 0.5)
			(thermal_bridge_width 0.5)
			(island_removal_mode 0)
		)
		(polygon
			(pts
				(xy 262.50011 -220.9165) (xy 262.50011 -220.472762) (xy 264.825226 -220.472762) (xy 264.825226 -220.9165)
			)
		)
	)
	(zone
		(layer "F.Cu")
		(hatch none 0.5)
		(connect_pads
			(clearance 0)
		)
		(min_thickness 0.25)
		(keepout
			(tracks allowed)
			(vias allowed)
			(pads allowed)
			(copperpour allowed)
			(footprints allowed)
		)
		(placement
			(enabled no)
			(sheetname "")
		)
		(fill
			(thermal_gap 0.5)
			(thermal_bridge_width 0.5)
			(island_removal_mode 0)
		)
		(polygon
			(pts
				(xy 289.231578 -237.916466) (xy 289.231578 -237.472728) (xy 291.556694 -237.472728) (xy 291.556694 -237.916466)
			)
		)
	)
	(zone
		(layer "F.Cu")
		(hatch none 0.5)
		(connect_pads
			(clearance 0)
		)
		(min_thickness 0.25)
		(keepout
			(tracks not_allowed)
			(vias allowed)
			(pads allowed)
			(copperpour not_allowed)
			(footprints allowed)
		)
		(placement
			(enabled no)
			(sheetname "")
		)
		(fill
			(thermal_gap 0.5)
			(thermal_bridge_width 0.5)
			(island_removal_mode 0)
		)
		(polygon
			(pts
				(xy 367.374678 -336.26044) (xy 371.31244 -336.26044) (xy 371.31244 -336.212688) (xy 371.17528 -336.075528)
				(xy 369.762532 -336.075528) (xy 369.762532 -333.916528) (xy 371.919246 -333.916528) (xy 371.919246 -333.666846)
				(xy 369.57254 -333.666846) (xy 369.57254 -333.987648) (xy 369.471194 -333.987648) (xy 369.471194 -336.019902)
				(xy 367.616994 -336.019902) (xy 367.616994 -335.778856) (xy 367.374678 -335.778856)
			)
		)
	)
	(zone
		(layer "F.Cu")
		(hatch none 0.5)
		(connect_pads
			(clearance 0)
		)
		(min_thickness 0.25)
		(keepout
			(tracks allowed)
			(vias allowed)
			(pads allowed)
			(copperpour allowed)
			(footprints not_allowed)
		)
		(placement
			(enabled no)
			(sheetname "")
		)
		(fill
			(thermal_gap 0.5)
			(thermal_bridge_width 0.5)
			(island_removal_mode 0)
		)
		(polygon
			(pts
				(arc
					(start 311.900062 -68.449952)
					(mid 316.900052 -63.449962)
					(end 321.900042 -68.449952)
				)
				(arc
					(start 321.900042 -68.449952)
					(mid 316.900052 -73.449942)
					(end 311.900062 -68.449952)
				)
			)
		)
	)
	(zone
		(layer "F.Cu")
		(hatch none 0.5)
		(connect_pads
			(clearance 0)
		)
		(min_thickness 0.25)
		(keepout
			(tracks allowed)
			(vias allowed)
			(pads allowed)
			(copperpour allowed)
			(footprints allowed)
		)
		(placement
			(enabled no)
			(sheetname "")
		)
		(fill
			(thermal_gap 0.5)
			(thermal_bridge_width 0.5)
			(island_removal_mode 0)
		)
		(polygon
			(pts
				(xy 307.76291 -231.966516) (xy 307.76291 -231.522778) (xy 310.088026 -231.522778) (xy 310.088026 -231.966516)
			)
		)
	)
	(zone
		(layer "F.Cu")
		(hatch none 0.5)
		(connect_pads
			(clearance 0)
		)
		(min_thickness 0.25)
		(keepout
			(tracks allowed)
			(vias allowed)
			(pads allowed)
			(copperpour allowed)
			(footprints allowed)
		)
		(placement
			(enabled no)
			(sheetname "")
		)
		(fill
			(thermal_gap 0.5)
			(thermal_bridge_width 0.5)
			(island_removal_mode 0)
		)
		(polygon
			(pts
				(xy 29.647642 -221.766638) (xy 29.647642 -221.3229) (xy 31.972758 -221.3229) (xy 31.972758 -221.766638)
			)
		)
	)
	(zone
		(layer "F.Cu")
		(hatch none 0.5)
		(connect_pads
			(clearance 0)
		)
		(min_thickness 0.25)
		(keepout
			(tracks allowed)
			(vias allowed)
			(pads allowed)
			(copperpour allowed)
			(footprints allowed)
		)
		(placement
			(enabled no)
			(sheetname "")
		)
		(fill
			(thermal_gap 0.5)
			(thermal_bridge_width 0.5)
			(island_removal_mode 0)
		)
		(polygon
			(pts
				(xy 11.11631 -250.666504) (xy 11.11631 -250.222766) (xy 13.441426 -250.222766) (xy 13.441426 -250.666504)
			)
		)
	)
	(zone
		(layer "F.Cu")
		(hatch none 0.5)
		(connect_pads
			(clearance 0)
		)
		(min_thickness 0.25)
		(keepout
			(tracks allowed)
			(vias allowed)
			(pads allowed)
			(copperpour allowed)
			(footprints allowed)
		)
		(placement
			(enabled no)
			(sheetname "")
		)
		(fill
			(thermal_gap 0.5)
			(thermal_bridge_width 0.5)
			(island_removal_mode 0)
		)
		(polygon
			(pts
				(xy 29.647642 -311.866534) (xy 29.647642 -311.422796) (xy 31.972758 -311.422796) (xy 31.972758 -311.866534)
			)
		)
	)
	(zone
		(layer "F.Cu")
		(hatch none 0.5)
		(connect_pads
			(clearance 0)
		)
		(min_thickness 0.25)
		(keepout
			(tracks allowed)
			(vias allowed)
			(pads allowed)
			(copperpour allowed)
			(footprints not_allowed)
		)
		(placement
			(enabled no)
			(sheetname "")
		)
		(fill
			(thermal_gap 0.5)
			(thermal_bridge_width 0.5)
			(island_removal_mode 0)
		)
		(polygon
			(pts
				(xy 404.753572 -328.521822) (xy 399.303494 -328.521822) (xy 399.303494 -347.521784)
				(arc
					(start 453.461882 -347.521784)
					(mid 458.603716 -340.227192)
					(end 467.300056 -342.232488)
				)
				(xy 467.300056 -328.521822) (xy 465.659978 -328.521822) (xy 465.659978 -331.091794) (xy 404.753572 -331.091794)
			)
		)
	)
	(zone
		(layer "F.Cu")
		(hatch none 0.5)
		(connect_pads
			(clearance 0)
		)
		(min_thickness 0.25)
		(keepout
			(tracks allowed)
			(vias allowed)
			(pads allowed)
			(copperpour allowed)
			(footprints allowed)
		)
		(placement
			(enabled no)
			(sheetname "")
		)
		(fill
			(thermal_gap 0.5)
			(thermal_bridge_width 0.5)
			(island_removal_mode 0)
		)
		(polygon
			(pts
				(xy 41.29151 -304.216562) (xy 41.29151 -303.772824) (xy 43.616626 -303.772824) (xy 43.616626 -304.216562)
			)
		)
	)
	(zone
		(layer "F.Cu")
		(hatch none 0.5)
		(connect_pads
			(clearance 0)
		)
		(min_thickness 0.25)
		(keepout
			(tracks allowed)
			(vias allowed)
			(pads allowed)
			(copperpour allowed)
			(footprints allowed)
		)
		(placement
			(enabled no)
			(sheetname "")
		)
		(fill
			(thermal_gap 0.5)
			(thermal_bridge_width 0.5)
			(island_removal_mode 0)
		)
		(polygon
			(pts
				(xy 41.29151 -305.066446) (xy 41.29151 -304.622708) (xy 43.616626 -304.622708) (xy 43.616626 -305.066446)
			)
		)
	)
	(zone
		(layer "F.Cu")
		(hatch none 0.5)
		(connect_pads
			(clearance 0)
		)
		(min_thickness 0.25)
		(keepout
			(tracks allowed)
			(vias allowed)
			(pads allowed)
			(copperpour allowed)
			(footprints allowed)
		)
		(placement
			(enabled no)
			(sheetname "")
		)
		(fill
			(thermal_gap 0.5)
			(thermal_bridge_width 0.5)
			(island_removal_mode 0)
		)
		(polygon
			(pts
				(xy 409.831794 -235.0262) (xy 411.863794 -235.0262) (xy 412.176976 -235.0262) (xy 412.176976 -235.711238)
				(xy 409.393644 -235.711238) (xy 409.393644 -235.0262)
			)
		)
	)
	(zone
		(layer "F.Cu")
		(hatch none 0.5)
		(connect_pads
			(clearance 0)
		)
		(min_thickness 0.25)
		(keepout
			(tracks allowed)
			(vias allowed)
			(pads allowed)
			(copperpour allowed)
			(footprints allowed)
		)
		(placement
			(enabled no)
			(sheetname "")
		)
		(fill
			(thermal_gap 0.5)
			(thermal_bridge_width 0.5)
			(island_removal_mode 0)
		)
		(polygon
			(pts
				(xy 443.450726 -198.704962) (xy 443.450726 -198.476362) (xy 445.482726 -198.476362) (xy 445.482726 -198.704962)
			)
		)
	)
	(zone
		(layer "F.Cu")
		(hatch none 0.5)
		(connect_pads
			(clearance 0)
		)
		(min_thickness 0.25)
		(keepout
			(tracks not_allowed)
			(vias allowed)
			(pads allowed)
			(copperpour not_allowed)
			(footprints allowed)
		)
		(placement
			(enabled no)
			(sheetname "")
		)
		(fill
			(thermal_gap 0.5)
			(thermal_bridge_width 0.5)
			(island_removal_mode 0)
		)
		(polygon
			(pts
				(xy 296.429938 -365.319818) (xy 300.36008 -365.319818) (xy 300.36008 -365.300006) (xy 300.19498 -365.134906)
				(xy 298.817792 -365.134906) (xy 298.817792 -362.975906) (xy 300.974506 -362.975906) (xy 300.974506 -362.726224)
				(xy 298.6405 -362.726224) (xy 298.6405 -363.045248) (xy 298.526454 -363.045248) (xy 298.526454 -365.07928)
				(xy 296.672254 -365.07928) (xy 296.672254 -364.838234) (xy 296.429938 -364.838234)
			)
		)
	)
	(zone
		(layer "F.Cu")
		(hatch none 0.5)
		(connect_pads
			(clearance 0)
		)
		(min_thickness 0.25)
		(keepout
			(tracks allowed)
			(vias allowed)
			(pads allowed)
			(copperpour allowed)
			(footprints allowed)
		)
		(placement
			(enabled no)
			(sheetname "")
		)
		(fill
			(thermal_gap 0.5)
			(thermal_bridge_width 0.5)
			(island_removal_mode 0)
		)
		(polygon
			(pts
				(xy 192.066926 -303.25695) (xy 194.098926 -303.25695) (xy 194.098926 -303.02835) (xy 192.066926 -303.02835)
				(xy 191.935608 -303.02835) (xy 191.9097 -303.02835) (xy 191.9097 -303.25695) (xy 191.935608 -303.25695)
			)
		)
	)
	(zone
		(layer "F.Cu")
		(hatch none 0.5)
		(connect_pads
			(clearance 0)
		)
		(min_thickness 0.25)
		(keepout
			(tracks allowed)
			(vias allowed)
			(pads allowed)
			(copperpour allowed)
			(footprints allowed)
		)
		(placement
			(enabled no)
			(sheetname "")
		)
		(fill
			(thermal_gap 0.5)
			(thermal_bridge_width 0.5)
			(island_removal_mode 0)
		)
		(polygon
			(pts
				(xy 29.647642 -209.0166) (xy 29.647642 -208.572862) (xy 31.972758 -208.572862) (xy 31.972758 -209.0166)
			)
		)
	)
	(zone
		(layer "F.Cu")
		(hatch none 0.5)
		(connect_pads
			(clearance 0)
		)
		(min_thickness 0.25)
		(keepout
			(tracks allowed)
			(vias allowed)
			(pads allowed)
			(copperpour allowed)
			(footprints allowed)
		)
		(placement
			(enabled no)
			(sheetname "")
		)
		(fill
			(thermal_gap 0.5)
			(thermal_bridge_width 0.5)
			(island_removal_mode 0)
		)
		(polygon
			(pts
				(xy 277.58771 -230.266494) (xy 277.58771 -229.822756) (xy 279.912826 -229.822756) (xy 279.912826 -230.266494)
			)
		)
	)
	(zone
		(layer "F.Cu")
		(hatch none 0.5)
		(connect_pads
			(clearance 0)
		)
		(min_thickness 0.25)
		(keepout
			(tracks allowed)
			(vias allowed)
			(pads allowed)
			(copperpour allowed)
			(footprints allowed)
		)
		(placement
			(enabled no)
			(sheetname "")
		)
		(fill
			(thermal_gap 0.5)
			(thermal_bridge_width 0.5)
			(island_removal_mode 0)
		)
		(polygon
			(pts
				(xy 259.056378 -245.566438) (xy 259.056378 -245.1227) (xy 261.381494 -245.1227) (xy 261.381494 -245.566438)
			)
		)
	)
	(zone
		(layer "F.Cu")
		(hatch none 0.5)
		(connect_pads
			(clearance 0)
		)
		(min_thickness 0.25)
		(keepout
			(tracks allowed)
			(vias allowed)
			(pads allowed)
			(copperpour allowed)
			(footprints allowed)
		)
		(placement
			(enabled no)
			(sheetname "")
		)
		(fill
			(thermal_gap 0.5)
			(thermal_bridge_width 0.5)
			(island_removal_mode 0)
		)
		(polygon
			(pts
				(xy 11.11631 -308.46649) (xy 11.11631 -308.022752) (xy 13.441426 -308.022752) (xy 13.441426 -308.46649)
			)
		)
	)
	(zone
		(layer "F.Cu")
		(hatch none 0.5)
		(connect_pads
			(clearance 0)
		)
		(min_thickness 0.25)
		(keepout
			(tracks allowed)
			(vias allowed)
			(pads allowed)
			(copperpour allowed)
			(footprints allowed)
		)
		(placement
			(enabled no)
			(sheetname "")
		)
		(fill
			(thermal_gap 0.5)
			(thermal_bridge_width 0.5)
			(island_removal_mode 0)
		)
		(polygon
			(pts
				(xy 192.066926 -195.926456) (xy 194.098926 -195.926456) (xy 194.098926 -196.155056) (xy 192.066926 -196.155056)
				(xy 191.930782 -196.155056) (xy 191.883792 -196.155056) (xy 191.883792 -195.926456) (xy 191.930782 -195.926456)
			)
		)
	)
	(zone
		(layer "F.Cu")
		(hatch none 0.5)
		(connect_pads
			(clearance 0)
		)
		(min_thickness 0.25)
		(keepout
			(tracks allowed)
			(vias allowed)
			(pads allowed)
			(copperpour allowed)
			(footprints allowed)
		)
		(placement
			(enabled no)
			(sheetname "")
		)
		(fill
			(thermal_gap 0.5)
			(thermal_bridge_width 0.5)
			(island_removal_mode 0)
		)
		(polygon
			(pts
				(xy 283.1338 -364.935008) (xy 283.1338 -362.120688) (xy 283.2608 -361.993688) (xy 283.68752 -361.993688)
				(xy 283.80182 -362.107988) (xy 283.80182 -364.874048) (xy 283.718 -364.957868) (xy 283.15666 -364.957868)
			)
		)
	)
	(zone
		(layer "F.Cu")
		(hatch none 0.5)
		(connect_pads
			(clearance 0)
		)
		(min_thickness 0.25)
		(keepout
			(tracks allowed)
			(vias allowed)
			(pads allowed)
			(copperpour allowed)
			(footprints allowed)
		)
		(placement
			(enabled no)
			(sheetname "")
		)
		(fill
			(thermal_gap 0.5)
			(thermal_bridge_width 0.5)
			(island_removal_mode 0)
		)
		(polygon
			(pts
				(xy 161.891726 -219.104972) (xy 161.891726 -218.876372) (xy 163.923726 -218.876372) (xy 163.923726 -219.104972)
			)
		)
	)
	(zone
		(layer "F.Cu")
		(hatch none 0.5)
		(connect_pads
			(clearance 0)
		)
		(min_thickness 0.25)
		(keepout
			(tracks allowed)
			(vias allowed)
			(pads allowed)
			(copperpour allowed)
			(footprints allowed)
		)
		(placement
			(enabled no)
			(sheetname "")
		)
		(fill
			(thermal_gap 0.5)
			(thermal_bridge_width 0.5)
			(island_removal_mode 0)
		)
		(polygon
			(pts
				(xy 428.363126 -205.504796) (xy 428.363126 -205.276196) (xy 430.395126 -205.276196) (xy 430.395126 -205.504796)
			)
		)
	)
	(zone
		(layer "F.Cu")
		(hatch none 0.5)
		(connect_pads
			(clearance 0)
		)
		(min_thickness 0.25)
		(keepout
			(tracks allowed)
			(vias allowed)
			(pads allowed)
			(copperpour allowed)
			(footprints allowed)
		)
		(placement
			(enabled no)
			(sheetname "")
		)
		(fill
			(thermal_gap 0.5)
			(thermal_bridge_width 0.5)
			(island_removal_mode 0)
		)
		(polygon
			(pts
				(xy 26.20391 -284.666436) (xy 26.20391 -284.222698) (xy 28.529026 -284.222698) (xy 28.529026 -284.666436)
			)
		)
	)
	(zone
		(layer "F.Cu")
		(hatch none 0.5)
		(connect_pads
			(clearance 0)
		)
		(min_thickness 0.25)
		(keepout
			(tracks allowed)
			(vias allowed)
			(pads allowed)
			(copperpour allowed)
			(footprints allowed)
		)
		(placement
			(enabled no)
			(sheetname "")
		)
		(fill
			(thermal_gap 0.5)
			(thermal_bridge_width 0.5)
			(island_removal_mode 0)
		)
		(polygon
			(pts
				(xy 360.62412 -398.4498) (xy 360.62412 -396.81658) (xy 362.01858 -396.81658) (xy 362.01858 -398.4498)
			)
		)
	)
	(zone
		(layer "F.Cu")
		(hatch none 0.5)
		(connect_pads
			(clearance 0)
		)
		(min_thickness 0.25)
		(keepout
			(tracks allowed)
			(vias allowed)
			(pads allowed)
			(copperpour allowed)
			(footprints allowed)
		)
		(placement
			(enabled no)
			(sheetname "")
		)
		(fill
			(thermal_gap 0.5)
			(thermal_bridge_width 0.5)
			(island_removal_mode 0)
		)
		(polygon
			(pts
				(xy 90.40622 -359.771188) (xy 90.40622 -357.188008) (xy 95.5675 -357.188008) (xy 95.5675 -359.771188)
			)
		)
	)
	(zone
		(layer "F.Cu")
		(hatch none 0.5)
		(connect_pads
			(clearance 0)
		)
		(min_thickness 0.25)
		(keepout
			(tracks allowed)
			(vias allowed)
			(pads allowed)
			(copperpour allowed)
			(footprints allowed)
		)
		(placement
			(enabled no)
			(sheetname "")
		)
		(fill
			(thermal_gap 0.5)
			(thermal_bridge_width 0.5)
			(island_removal_mode 0)
		)
		(polygon
			(pts
				(xy 183.20512 -402.16328) (xy 183.20512 -401.01012) (xy 184.7977 -401.01012) (xy 184.7977 -402.16328)
			)
		)
	)
	(zone
		(layer "F.Cu")
		(hatch none 0.5)
		(connect_pads
			(clearance 0)
		)
		(min_thickness 0.25)
		(keepout
			(tracks allowed)
			(vias allowed)
			(pads allowed)
			(copperpour allowed)
			(footprints allowed)
		)
		(placement
			(enabled no)
			(sheetname "")
		)
		(fill
			(thermal_gap 0.5)
			(thermal_bridge_width 0.5)
			(island_removal_mode 0)
		)
		(polygon
			(pts
				(xy 165.335458 -297.304968) (xy 165.335458 -297.076368) (xy 167.367458 -297.076368) (xy 167.367458 -297.304968)
			)
		)
	)
	(zone
		(layer "F.Cu")
		(hatch none 0.5)
		(connect_pads
			(clearance 0)
		)
		(min_thickness 0.25)
		(keepout
			(tracks allowed)
			(vias allowed)
			(pads allowed)
			(copperpour allowed)
			(footprints allowed)
		)
		(placement
			(enabled no)
			(sheetname "")
		)
		(fill
			(thermal_gap 0.5)
			(thermal_bridge_width 0.5)
			(island_removal_mode 0)
		)
		(polygon
			(pts
				(xy 407.724864 -404.802594) (xy 407.724864 -399.959576) (xy 409.60929 -399.959576) (xy 409.60929 -404.802594)
			)
		)
	)
	(zone
		(layer "F.Cu")
		(hatch none 0.5)
		(connect_pads
			(clearance 0)
		)
		(min_thickness 0.25)
		(keepout
			(tracks allowed)
			(vias allowed)
			(pads allowed)
			(copperpour allowed)
			(footprints allowed)
		)
		(placement
			(enabled no)
			(sheetname "")
		)
		(fill
			(thermal_gap 0.5)
			(thermal_bridge_width 0.5)
			(island_removal_mode 0)
		)
		(polygon
			(pts
				(xy 176.979326 -212.926422) (xy 179.011326 -212.926422) (xy 179.011326 -213.155022) (xy 176.979326 -213.155022)
				(xy 176.843182 -213.155022) (xy 176.796192 -213.155022) (xy 176.796192 -212.926422) (xy 176.843182 -212.926422)
			)
		)
	)
	(zone
		(layer "F.Cu")
		(hatch none 0.5)
		(connect_pads
			(clearance 0)
		)
		(min_thickness 0.25)
		(keepout
			(tracks allowed)
			(vias allowed)
			(pads allowed)
			(copperpour allowed)
			(footprints allowed)
		)
		(placement
			(enabled no)
			(sheetname "")
		)
		(fill
			(thermal_gap 0.5)
			(thermal_bridge_width 0.5)
			(island_removal_mode 0)
		)
		(polygon
			(pts
				(xy 388.189216 -244.867176) (xy 388.571486 -244.867176) (xy 390.595866 -242.842542) (xy 392.510264 -242.842542)
				(xy 393.831572 -241.521234) (xy 394.255752 -241.521234) (xy 394.255752 -241.520472) (xy 394.296646 -241.520472)
				(xy 394.296646 -240.860834) (xy 394.890752 -240.860834) (xy 394.96238 -240.860834) (xy 394.96238 -240.400332)
				(xy 395.295882 -240.06683) (xy 395.295882 -239.973104) (xy 395.295882 -239.012222) (xy 395.881352 -238.426752)
				(xy 395.96568 -238.342424) (xy 395.96568 -235.950506) (xy 396.186152 -235.730034) (xy 396.260066 -235.65612)
				(xy 396.260066 -234.74172) (xy 396.490952 -234.510834) (xy 396.58417 -234.417616) (xy 396.075154 -233.9086)
				(xy 395.981936 -234.001818) (xy 393.88796 -236.09554) (xy 393.880848 -236.102652) (xy 390.93013 -239.05337)
				(xy 389.105902 -239.05337) (xy 389.068056 -239.091216) (xy 388.86765 -239.091216) (xy 388.20725 -239.751616)
				(xy 388.20725 -239.886744) (xy 388.442962 -240.122456) (xy 388.442962 -240.207546) (xy 388.19709 -240.453418)
				(xy 388.19709 -240.54054) (xy 388.72668 -241.07013) (xy 388.7724 -241.07013) (xy 389.476488 -240.366042)
				(xy 389.900414 -240.366042) (xy 389.954262 -240.41989) (xy 389.954262 -240.983008) (xy 389.922512 -241.014758)
				(xy 389.642858 -241.014758) (xy 388.583678 -242.073938) (xy 388.583678 -242.115086) (xy 388.923022 -242.45443)
				(xy 388.923022 -242.614958) (xy 388.189216 -243.348764)
			)
		)
	)
	(zone
		(layer "F.Cu")
		(hatch none 0.5)
		(connect_pads
			(clearance 0)
		)
		(min_thickness 0.25)
		(keepout
			(tracks allowed)
			(vias allowed)
			(pads allowed)
			(copperpour allowed)
			(footprints allowed)
		)
		(placement
			(enabled no)
			(sheetname "")
		)
		(fill
			(thermal_gap 0.5)
			(thermal_bridge_width 0.5)
			(island_removal_mode 0)
		)
		(polygon
			(pts
				(xy 62.147958 -239.616488) (xy 59.822842 -239.616488) (xy 59.515248 -239.616488) (xy 59.515248 -238.641382)
				(xy 62.42685 -238.641382) (xy 62.42685 -239.616488)
			)
		)
	)
	(zone
		(layer "F.Cu")
		(hatch none 0.5)
		(connect_pads
			(clearance 0)
		)
		(min_thickness 0.25)
		(keepout
			(tracks allowed)
			(vias allowed)
			(pads allowed)
			(copperpour allowed)
			(footprints allowed)
		)
		(placement
			(enabled no)
			(sheetname "")
		)
		(fill
			(thermal_gap 0.5)
			(thermal_bridge_width 0.5)
			(island_removal_mode 0)
		)
		(polygon
			(pts
				(xy 59.822842 -305.916584) (xy 59.822842 -305.472846) (xy 62.147958 -305.472846) (xy 62.147958 -305.916584)
			)
		)
	)
	(zone
		(layer "F.Cu")
		(hatch none 0.5)
		(connect_pads
			(clearance 0)
		)
		(min_thickness 0.25)
		(keepout
			(tracks allowed)
			(vias allowed)
			(pads allowed)
			(copperpour allowed)
			(footprints allowed)
		)
		(placement
			(enabled no)
			(sheetname "")
		)
		(fill
			(thermal_gap 0.5)
			(thermal_bridge_width 0.5)
			(island_removal_mode 0)
		)
		(polygon
			(pts
				(xy 41.29151 -310.166512) (xy 41.29151 -309.722774) (xy 43.616626 -309.722774) (xy 43.616626 -310.166512)
			)
		)
	)
	(zone
		(layer "F.Cu")
		(hatch none 0.5)
		(connect_pads
			(clearance 0)
		)
		(min_thickness 0.25)
		(keepout
			(tracks allowed)
			(vias allowed)
			(pads allowed)
			(copperpour allowed)
			(footprints allowed)
		)
		(placement
			(enabled no)
			(sheetname "")
		)
		(fill
			(thermal_gap 0.5)
			(thermal_bridge_width 0.5)
			(island_removal_mode 0)
		)
		(polygon
			(pts
				(xy 207.154526 -239.276382) (xy 209.186526 -239.276382) (xy 209.186526 -239.504982) (xy 207.154526 -239.504982)
				(xy 207.018382 -239.504982) (xy 206.971392 -239.504982) (xy 206.971392 -239.276382) (xy 207.018382 -239.276382)
			)
		)
	)
	(zone
		(layer "F.Cu")
		(hatch none 0.5)
		(connect_pads
			(clearance 0)
		)
		(min_thickness 0.25)
		(keepout
			(tracks allowed)
			(vias allowed)
			(pads allowed)
			(copperpour allowed)
			(footprints allowed)
		)
		(placement
			(enabled no)
			(sheetname "")
		)
		(fill
			(thermal_gap 0.5)
			(thermal_bridge_width 0.5)
			(island_removal_mode 0)
		)
		(polygon
			(pts
				(xy 277.58771 -227.716588) (xy 277.58771 -227.27285) (xy 279.912826 -227.27285) (xy 279.912826 -227.716588)
			)
		)
	)
	(zone
		(layer "F.Cu")
		(hatch none 0.5)
		(connect_pads
			(clearance 0)
		)
		(min_thickness 0.25)
		(keepout
			(tracks allowed)
			(vias allowed)
			(pads allowed)
			(copperpour allowed)
			(footprints allowed)
		)
		(placement
			(enabled no)
			(sheetname "")
		)
		(fill
			(thermal_gap 0.5)
			(thermal_bridge_width 0.5)
			(island_removal_mode 0)
		)
		(polygon
			(pts
				(xy 44.203366 -353.418394) (xy 40.667686 -353.418394) (xy 40.667686 -351.335594) (xy 44.203366 -351.335594)
			)
		)
	)
	(zone
		(layer "F.Cu")
		(hatch none 0.5)
		(connect_pads
			(clearance 0)
		)
		(min_thickness 0.25)
		(keepout
			(tracks allowed)
			(vias allowed)
			(pads allowed)
			(copperpour allowed)
			(footprints allowed)
		)
		(placement
			(enabled no)
			(sheetname "")
		)
		(fill
			(thermal_gap 0.5)
			(thermal_bridge_width 0.5)
			(island_removal_mode 0)
		)
		(polygon
			(pts
				(xy 127.106934 -335.09966) (xy 127.106934 -339.10524) (xy 127.586994 -339.5853) (xy 129.652014 -339.5853)
				(xy 129.923794 -339.31352) (xy 129.923794 -337.45932) (xy 130.175254 -337.20786) (xy 132.095494 -337.20786)
				(xy 132.512054 -336.7913) (xy 132.512054 -335.30032) (xy 131.864354 -334.65262) (xy 127.553974 -334.65262)
			)
		)
	)
	(zone
		(layer "F.Cu")
		(hatch none 0.5)
		(connect_pads
			(clearance 0)
		)
		(min_thickness 0.25)
		(keepout
			(tracks allowed)
			(vias allowed)
			(pads allowed)
			(copperpour allowed)
			(footprints allowed)
		)
		(placement
			(enabled no)
			(sheetname "")
		)
		(fill
			(thermal_gap 0.5)
			(thermal_bridge_width 0.5)
			(island_removal_mode 0)
		)
		(polygon
			(pts
				(xy 192.066926 -200.407016) (xy 194.098926 -200.407016) (xy 194.098926 -200.178416) (xy 192.066926 -200.178416)
				(xy 191.935608 -200.178416) (xy 191.9097 -200.178416) (xy 191.9097 -200.407016) (xy 191.935608 -200.407016)
			)
		)
	)
	(zone
		(layer "F.Cu")
		(hatch none 0.5)
		(connect_pads
			(clearance 0)
		)
		(min_thickness 0.25)
		(keepout
			(tracks allowed)
			(vias allowed)
			(pads allowed)
			(copperpour allowed)
			(footprints not_allowed)
		)
		(placement
			(enabled no)
			(sheetname "")
		)
		(fill
			(thermal_gap 0.5)
			(thermal_bridge_width 0.5)
			(island_removal_mode 0)
		)
		(polygon
			(pts
				(xy 428.38497 -330.091796) (xy 434.48478 -330.091796) (xy 434.48478 -186.09183) (xy 428.38497 -186.09183)
			)
		)
	)
	(zone
		(layer "F.Cu")
		(hatch none 0.5)
		(connect_pads
			(clearance 0)
		)
		(min_thickness 0.25)
		(keepout
			(tracks allowed)
			(vias allowed)
			(pads allowed)
			(copperpour allowed)
			(footprints allowed)
		)
		(placement
			(enabled no)
			(sheetname "")
		)
		(fill
			(thermal_gap 0.5)
			(thermal_bridge_width 0.5)
			(island_removal_mode 0)
		)
		(polygon
			(pts
				(xy 440.006994 -247.776238) (xy 442.038994 -247.776238) (xy 442.038994 -248.004838) (xy 440.006994 -248.004838)
				(xy 439.84037 -248.004838) (xy 439.84037 -247.776238)
			)
		)
	)
	(zone
		(layer "F.Cu")
		(hatch none 0.5)
		(connect_pads
			(clearance 0)
		)
		(min_thickness 0.25)
		(keepout
			(tracks allowed)
			(vias allowed)
			(pads allowed)
			(copperpour allowed)
			(footprints allowed)
		)
		(placement
			(enabled no)
			(sheetname "")
		)
		(fill
			(thermal_gap 0.5)
			(thermal_bridge_width 0.5)
			(island_removal_mode 0)
		)
		(polygon
			(pts
				(xy 63.977012 -246.416576) (xy 63.977012 -245.972838) (xy 66.186812 -245.972838) (xy 66.186812 -246.416576)
			)
		)
	)
	(zone
		(layer "F.Cu")
		(hatch none 0.5)
		(connect_pads
			(clearance 0)
		)
		(min_thickness 0.25)
		(keepout
			(tracks allowed)
			(vias allowed)
			(pads allowed)
			(copperpour allowed)
			(footprints allowed)
		)
		(placement
			(enabled no)
			(sheetname "")
		)
		(fill
			(thermal_gap 0.5)
			(thermal_bridge_width 0.5)
			(island_removal_mode 0)
		)
		(polygon
			(pts
				(xy 14.560042 -280.416508) (xy 14.560042 -279.97277) (xy 16.885158 -279.97277) (xy 16.885158 -280.416508)
			)
		)
	)
	(zone
		(layer "F.Cu")
		(hatch none 0.5)
		(connect_pads
			(clearance 0)
		)
		(min_thickness 0.25)
		(keepout
			(tracks allowed)
			(vias allowed)
			(pads allowed)
			(copperpour allowed)
			(footprints allowed)
		)
		(placement
			(enabled no)
			(sheetname "")
		)
		(fill
			(thermal_gap 0.5)
			(thermal_bridge_width 0.5)
			(island_removal_mode 0)
		)
		(polygon
			(pts
				(xy 29.647642 -311.01665) (xy 29.647642 -310.572912) (xy 31.972758 -310.572912) (xy 31.972758 -311.01665)
			)
		)
	)
	(zone
		(layer "F.Cu")
		(hatch none 0.5)
		(connect_pads
			(clearance 0)
		)
		(min_thickness 0.25)
		(keepout
			(tracks allowed)
			(vias allowed)
			(pads allowed)
			(copperpour allowed)
			(footprints allowed)
		)
		(placement
			(enabled no)
			(sheetname "")
		)
		(fill
			(thermal_gap 0.5)
			(thermal_bridge_width 0.5)
			(island_removal_mode 0)
		)
		(polygon
			(pts
				(xy 139.122658 -271.83715) (xy 138.919712 -271.634204) (xy 138.876532 -271.634204) (xy 138.432794 -272.077942)
				(xy 138.432794 -272.200116) (xy 138.56589 -272.332958) (xy 138.67003 -272.332958) (xy 139.122658 -271.88033)
			)
		)
	)
	(zone
		(layer "F.Cu")
		(hatch none 0.5)
		(connect_pads
			(clearance 0)
		)
		(min_thickness 0.25)
		(keepout
			(tracks allowed)
			(vias allowed)
			(pads allowed)
			(copperpour allowed)
			(footprints allowed)
		)
		(placement
			(enabled no)
			(sheetname "")
		)
		(fill
			(thermal_gap 0.5)
			(thermal_bridge_width 0.5)
			(island_removal_mode 0)
		)
		(polygon
			(pts
				(xy 210.598258 -247.154954) (xy 210.598258 -246.926354) (xy 212.630258 -246.926354) (xy 212.630258 -247.154954)
			)
		)
	)
	(zone
		(layer "F.Cu")
		(hatch none 0.5)
		(connect_pads
			(clearance 0)
		)
		(min_thickness 0.25)
		(keepout
			(tracks allowed)
			(vias allowed)
			(pads allowed)
			(copperpour allowed)
			(footprints allowed)
		)
		(placement
			(enabled no)
			(sheetname "")
		)
		(fill
			(thermal_gap 0.5)
			(thermal_bridge_width 0.5)
			(island_removal_mode 0)
		)
		(polygon
			(pts
				(xy 412.1277 -12.830048) (xy 412.1277 -9.982708) (xy 420.45636 -9.982708) (xy 420.45636 -12.830048)
			)
		)
	)
	(zone
		(layer "F.Cu")
		(hatch none 0.5)
		(connect_pads
			(clearance 0)
		)
		(min_thickness 0.25)
		(keepout
			(tracks not_allowed)
			(vias allowed)
			(pads allowed)
			(copperpour not_allowed)
			(footprints allowed)
		)
		(placement
			(enabled no)
			(sheetname "")
		)
		(fill
			(thermal_gap 0.5)
			(thermal_bridge_width 0.5)
			(island_removal_mode 0)
		)
		(polygon
			(pts
				(xy 54.699154 -158.978092) (xy 54.948836 -158.978092) (xy 54.948836 -156.708348) (xy 54.63286 -156.708348)
				(xy 54.63286 -156.53004) (xy 52.59578 -156.53004) (xy 52.59578 -154.67584) (xy 52.836826 -154.67584)
				(xy 52.836826 -154.433524) (xy 52.355242 -154.433524) (xy 52.355242 -158.382208) (xy 52.540154 -158.197296)
				(xy 52.540154 -156.821378) (xy 54.699154 -156.821378)
			)
		)
	)
	(zone
		(layer "F.Cu")
		(hatch none 0.5)
		(connect_pads
			(clearance 0)
		)
		(min_thickness 0.25)
		(keepout
			(tracks allowed)
			(vias allowed)
			(pads allowed)
			(copperpour allowed)
			(footprints allowed)
		)
		(placement
			(enabled no)
			(sheetname "")
		)
		(fill
			(thermal_gap 0.5)
			(thermal_bridge_width 0.5)
			(island_removal_mode 0)
		)
		(polygon
			(pts
				(xy 85.21954 -218.704668) (xy 85.50656 -218.704668) (xy 85.53704 -218.674188) (xy 85.53704 -218.046808)
				(xy 85.45068 -217.960448) (xy 85.26272 -217.960448) (xy 85.18906 -218.034108) (xy 85.18906 -218.674188)
			)
		)
	)
	(zone
		(layer "F.Cu")
		(hatch none 0.5)
		(connect_pads
			(clearance 0)
		)
		(min_thickness 0.25)
		(keepout
			(tracks allowed)
			(vias allowed)
			(pads allowed)
			(copperpour allowed)
			(footprints allowed)
		)
		(placement
			(enabled no)
			(sheetname "")
		)
		(fill
			(thermal_gap 0.5)
			(thermal_bridge_width 0.5)
			(island_removal_mode 0)
		)
		(polygon
			(pts
				(xy 440.006994 -270.726408) (xy 442.038994 -270.726408) (xy 442.038994 -270.728694) (xy 442.21781 -270.728694)
				(xy 442.21781 -270.96593) (xy 442.355732 -270.96593) (xy 442.398912 -271.00911) (xy 442.398912 -271.141952)
				(xy 442.398912 -271.44599) (xy 442.326268 -271.518634) (xy 439.786014 -271.518634) (xy 439.64479 -271.37741)
				(xy 439.64479 -271.180306) (xy 439.726324 -271.098772) (xy 439.726324 -270.726408) (xy 439.82386 -270.726408)
				(xy 439.87085 -270.726408)
			)
		)
	)
	(zone
		(layer "F.Cu")
		(hatch none 0.5)
		(connect_pads
			(clearance 0)
		)
		(min_thickness 0.25)
		(keepout
			(tracks allowed)
			(vias allowed)
			(pads allowed)
			(copperpour allowed)
			(footprints not_allowed)
		)
		(placement
			(enabled no)
			(sheetname "")
		)
		(fill
			(thermal_gap 0.5)
			(thermal_bridge_width 0.5)
			(island_removal_mode 0)
		)
		(polygon
			(pts
				(arc
					(start 102.899972 -22.29993)
					(mid 94.899988 -30.299914)
					(end 86.900004 -22.29993)
				)
				(arc
					(start 86.900004 -22.29993)
					(mid 94.899988 -14.299946)
					(end 102.899972 -22.29993)
				)
			)
		)
	)
	(zone
		(layer "F.Cu")
		(hatch none 0.5)
		(connect_pads
			(clearance 0)
		)
		(min_thickness 0.25)
		(keepout
			(tracks allowed)
			(vias allowed)
			(pads allowed)
			(copperpour allowed)
			(footprints allowed)
		)
		(placement
			(enabled no)
			(sheetname "")
		)
		(fill
			(thermal_gap 0.5)
			(thermal_bridge_width 0.5)
			(island_removal_mode 0)
		)
		(polygon
			(pts
				(xy 257.54838 -396.466568) (xy 257.54838 -393.189968) (xy 260.94944 -393.189968) (xy 260.94944 -396.466568)
			)
		)
	)
	(zone
		(layer "F.Cu")
		(hatch none 0.5)
		(connect_pads
			(clearance 0)
		)
		(min_thickness 0.25)
		(keepout
			(tracks not_allowed)
			(vias allowed)
			(pads allowed)
			(copperpour not_allowed)
			(footprints allowed)
		)
		(placement
			(enabled no)
			(sheetname "")
		)
		(fill
			(thermal_gap 0.5)
			(thermal_bridge_width 0.5)
			(island_removal_mode 0)
		)
		(polygon
			(pts
				(xy 235.4199 -252.123448) (xy 235.4199 -251.927868) (xy 236.69498 -251.927868) (xy 236.69498 -252.123448)
			)
		)
	)
	(zone
		(layer "F.Cu")
		(hatch none 0.5)
		(connect_pads
			(clearance 0)
		)
		(min_thickness 0.25)
		(keepout
			(tracks allowed)
			(vias allowed)
			(pads allowed)
			(copperpour allowed)
			(footprints allowed)
		)
		(placement
			(enabled no)
			(sheetname "")
		)
		(fill
			(thermal_gap 0.5)
			(thermal_bridge_width 0.5)
			(island_removal_mode 0)
		)
		(polygon
			(pts
				(xy 135.014208 -404.802594) (xy 135.014208 -399.959576) (xy 136.898634 -399.959576) (xy 136.898634 -404.802594)
			)
		)
	)
	(zone
		(layer "F.Cu")
		(hatch none 0.5)
		(connect_pads
			(clearance 0)
		)
		(min_thickness 0.25)
		(keepout
			(tracks allowed)
			(vias allowed)
			(pads allowed)
			(copperpour allowed)
			(footprints allowed)
		)
		(placement
			(enabled no)
			(sheetname "")
		)
		(fill
			(thermal_gap 0.5)
			(thermal_bridge_width 0.5)
			(island_removal_mode 0)
		)
		(polygon
			(pts
				(xy 292.67531 -234.516422) (xy 292.67531 -234.072684) (xy 295.000426 -234.072684) (xy 295.000426 -234.516422)
			)
		)
	)
	(zone
		(layer "F.Cu")
		(hatch none 0.5)
		(connect_pads
			(clearance 0)
		)
		(min_thickness 0.25)
		(keepout
			(tracks not_allowed)
			(vias allowed)
			(pads allowed)
			(copperpour not_allowed)
			(footprints allowed)
		)
		(placement
			(enabled no)
			(sheetname "")
		)
		(fill
			(thermal_gap 0.5)
			(thermal_bridge_width 0.5)
			(island_removal_mode 0)
		)
		(polygon
			(pts
				(arc
					(start 369.298474 -435.59984)
					(mid 371.29847 -433.599844)
					(end 373.298466 -435.59984)
				)
				(arc
					(start 373.298466 -435.59984)
					(mid 371.29847 -437.599836)
					(end 369.298474 -435.59984)
				)
			)
		)
	)
	(zone
		(layer "F.Cu")
		(hatch none 0.5)
		(connect_pads
			(clearance 0)
		)
		(min_thickness 0.25)
		(keepout
			(tracks allowed)
			(vias allowed)
			(pads allowed)
			(copperpour allowed)
			(footprints allowed)
		)
		(placement
			(enabled no)
			(sheetname "")
		)
		(fill
			(thermal_gap 0.5)
			(thermal_bridge_width 0.5)
			(island_removal_mode 0)
		)
		(polygon
			(pts
				(xy 192.066926 -201.876406) (xy 194.098926 -201.876406) (xy 194.098926 -202.105006) (xy 192.066926 -202.105006)
				(xy 191.930782 -202.105006) (xy 191.883792 -202.105006) (xy 191.883792 -201.876406) (xy 191.930782 -201.876406)
			)
		)
	)
	(zone
		(layer "F.Cu")
		(hatch none 0.5)
		(connect_pads
			(clearance 0)
		)
		(min_thickness 0.25)
		(keepout
			(tracks allowed)
			(vias allowed)
			(pads allowed)
			(copperpour allowed)
			(footprints allowed)
		)
		(placement
			(enabled no)
			(sheetname "")
		)
		(fill
			(thermal_gap 0.5)
			(thermal_bridge_width 0.5)
			(island_removal_mode 0)
		)
		(polygon
			(pts
				(xy 29.647642 -250.666504) (xy 29.647642 -250.222766) (xy 31.972758 -250.222766) (xy 31.972758 -250.666504)
			)
		)
	)
	(zone
		(layer "F.Cu")
		(hatch none 0.5)
		(connect_pads
			(clearance 0)
		)
		(min_thickness 0.25)
		(keepout
			(tracks allowed)
			(vias allowed)
			(pads allowed)
			(copperpour allowed)
			(footprints allowed)
		)
		(placement
			(enabled no)
			(sheetname "")
		)
		(fill
			(thermal_gap 0.5)
			(thermal_bridge_width 0.5)
			(island_removal_mode 0)
		)
		(polygon
			(pts
				(xy 443.450726 -203.805028) (xy 443.450726 -203.576428) (xy 445.482726 -203.576428) (xy 445.482726 -203.805028)
			)
		)
	)
	(zone
		(layer "F.Cu")
		(hatch none 0.5)
		(connect_pads
			(clearance 0)
		)
		(min_thickness 0.25)
		(keepout
			(tracks allowed)
			(vias allowed)
			(pads allowed)
			(copperpour allowed)
			(footprints allowed)
		)
		(placement
			(enabled no)
			(sheetname "")
		)
		(fill
			(thermal_gap 0.5)
			(thermal_bridge_width 0.5)
			(island_removal_mode 0)
		)
		(polygon
			(pts
				(xy 443.450726 -289.654996) (xy 443.450726 -289.426396) (xy 445.482726 -289.426396) (xy 445.482726 -289.654996)
			)
		)
	)
	(zone
		(layer "F.Cu")
		(hatch none 0.5)
		(connect_pads
			(clearance 0)
		)
		(min_thickness 0.25)
		(keepout
			(tracks allowed)
			(vias allowed)
			(pads allowed)
			(copperpour allowed)
			(footprints allowed)
		)
		(placement
			(enabled no)
			(sheetname "")
		)
		(fill
			(thermal_gap 0.5)
			(thermal_bridge_width 0.5)
			(island_removal_mode 0)
		)
		(polygon
			(pts
				(xy 334.6704 -285.824168) (xy 334.95742 -285.824168) (xy 334.9879 -285.793688) (xy 334.9879 -285.166308)
				(xy 334.90154 -285.079948) (xy 334.71358 -285.079948) (xy 334.63992 -285.153608) (xy 334.63992 -285.793688)
			)
		)
	)
	(zone
		(layer "F.Cu")
		(hatch none 0.5)
		(connect_pads
			(clearance 0)
		)
		(min_thickness 0.25)
		(keepout
			(tracks allowed)
			(vias allowed)
			(pads allowed)
			(copperpour allowed)
			(footprints not_allowed)
		)
		(placement
			(enabled no)
			(sheetname "")
		)
		(fill
			(thermal_gap 0.5)
			(thermal_bridge_width 0.5)
			(island_removal_mode 0)
		)
		(polygon
			(pts
				(xy 50.88001 -41.550082) (xy 50.88001 -52.55006) (xy 76.630022 -52.55006) (xy 76.63307 -41.550082)
			)
		)
	)
	(zone
		(layer "F.Cu")
		(hatch none 0.5)
		(connect_pads
			(clearance 0)
		)
		(min_thickness 0.25)
		(keepout
			(tracks allowed)
			(vias allowed)
			(pads allowed)
			(copperpour allowed)
			(footprints allowed)
		)
		(placement
			(enabled no)
			(sheetname "")
		)
		(fill
			(thermal_gap 0.5)
			(thermal_bridge_width 0.5)
			(island_removal_mode 0)
		)
		(polygon
			(pts
				(xy 195.510658 -199.554846) (xy 195.510658 -199.326246) (xy 197.542658 -199.326246) (xy 197.542658 -199.554846)
			)
		)
	)
	(zone
		(layer "F.Cu")
		(hatch none 0.5)
		(connect_pads
			(clearance 0)
		)
		(min_thickness 0.25)
		(keepout
			(tracks allowed)
			(vias allowed)
			(pads allowed)
			(copperpour allowed)
			(footprints allowed)
		)
		(placement
			(enabled no)
			(sheetname "")
		)
		(fill
			(thermal_gap 0.5)
			(thermal_bridge_width 0.5)
			(island_removal_mode 0)
		)
		(polygon
			(pts
				(xy 136.51738 -285.786068) (xy 136.8044 -285.786068) (xy 136.83488 -285.755588) (xy 136.83488 -285.128208)
				(xy 136.74852 -285.041848) (xy 136.56056 -285.041848) (xy 136.4869 -285.115508) (xy 136.4869 -285.755588)
			)
		)
	)
	(zone
		(layer "F.Cu")
		(hatch none 0.5)
		(connect_pads
			(clearance 0)
		)
		(min_thickness 0.25)
		(keepout
			(tracks allowed)
			(vias allowed)
			(pads allowed)
			(copperpour allowed)
			(footprints allowed)
		)
		(placement
			(enabled no)
			(sheetname "")
		)
		(fill
			(thermal_gap 0.5)
			(thermal_bridge_width 0.5)
			(island_removal_mode 0)
		)
		(polygon
			(pts
				(xy 84.906358 -256.039366) (xy 85.109304 -255.83642) (xy 85.109304 -255.79324) (xy 84.665566 -255.349502)
				(xy 84.543392 -255.349502) (xy 84.41055 -255.482598) (xy 84.41055 -255.586738) (xy 84.863178 -256.039366)
			)
		)
	)
	(zone
		(layer "F.Cu")
		(hatch none 0.5)
		(connect_pads
			(clearance 0)
		)
		(min_thickness 0.25)
		(keepout
			(tracks allowed)
			(vias allowed)
			(pads allowed)
			(copperpour allowed)
			(footprints allowed)
		)
		(placement
			(enabled no)
			(sheetname "")
		)
		(fill
			(thermal_gap 0.5)
			(thermal_bridge_width 0.5)
			(island_removal_mode 0)
		)
		(polygon
			(pts
				(xy 157.791658 -287.954974) (xy 157.791658 -287.726374) (xy 159.823658 -287.726374) (xy 159.823658 -287.954974)
			)
		)
	)
	(zone
		(layer "F.Cu")
		(hatch none 0.5)
		(connect_pads
			(clearance 0)
		)
		(min_thickness 0.25)
		(keepout
			(tracks allowed)
			(vias allowed)
			(pads allowed)
			(copperpour allowed)
			(footprints allowed)
		)
		(placement
			(enabled no)
			(sheetname "")
		)
		(fill
			(thermal_gap 0.5)
			(thermal_bridge_width 0.5)
			(island_removal_mode 0)
		)
		(polygon
			(pts
				(xy 440.006994 -219.107004) (xy 442.038994 -219.107004) (xy 442.038994 -218.878404) (xy 440.006994 -218.878404)
				(xy 439.875676 -218.878404) (xy 439.849768 -218.878404) (xy 439.849768 -219.107004) (xy 439.875676 -219.107004)
			)
		)
	)
	(zone
		(layer "F.Cu")
		(hatch none 0.5)
		(connect_pads
			(clearance 0)
		)
		(min_thickness 0.25)
		(keepout
			(tracks allowed)
			(vias allowed)
			(pads allowed)
			(copperpour allowed)
			(footprints allowed)
		)
		(placement
			(enabled no)
			(sheetname "")
		)
		(fill
			(thermal_gap 0.5)
			(thermal_bridge_width 0.5)
			(island_removal_mode 0)
		)
		(polygon
			(pts
				(xy 415.201862 -180.34254) (xy 415.201862 -182.15864) (xy 413.822642 -182.15864) (xy 413.822642 -180.34254)
			)
		)
	)
	(zone
		(layer "F.Cu")
		(hatch none 0.5)
		(connect_pads
			(clearance 0)
		)
		(min_thickness 0.25)
		(keepout
			(tracks allowed)
			(vias allowed)
			(pads allowed)
			(copperpour allowed)
			(footprints allowed)
		)
		(placement
			(enabled no)
			(sheetname "")
		)
		(fill
			(thermal_gap 0.5)
			(thermal_bridge_width 0.5)
			(island_removal_mode 0)
		)
		(polygon
			(pts
				(xy 11.11631 -200.51649) (xy 11.11631 -200.072752) (xy 13.441426 -200.072752) (xy 13.441426 -200.51649)
			)
		)
	)
	(zone
		(layer "F.Cu")
		(hatch none 0.5)
		(connect_pads
			(clearance 0)
		)
		(min_thickness 0.25)
		(keepout
			(tracks allowed)
			(vias allowed)
			(pads allowed)
			(copperpour allowed)
			(footprints allowed)
		)
		(placement
			(enabled no)
			(sheetname "")
		)
		(fill
			(thermal_gap 0.5)
			(thermal_bridge_width 0.5)
			(island_removal_mode 0)
		)
		(polygon
			(pts
				(xy 440.5249 -27.318208) (xy 444.51016 -27.318208) (xy 444.51016 -29.065728) (xy 440.5249 -29.065728)
			)
		)
	)
	(zone
		(layer "F.Cu")
		(hatch none 0.5)
		(connect_pads
			(clearance 0)
		)
		(min_thickness 0.25)
		(keepout
			(tracks allowed)
			(vias allowed)
			(pads allowed)
			(copperpour allowed)
			(footprints allowed)
		)
		(placement
			(enabled no)
			(sheetname "")
		)
		(fill
			(thermal_gap 0.5)
			(thermal_bridge_width 0.5)
			(island_removal_mode 0)
		)
		(polygon
			(pts
				(xy 257.5687 -396.461488) (xy 257.5687 -393.172188) (xy 260.99008 -393.172188) (xy 260.99008 -396.461488)
			)
		)
	)
	(zone
		(layer "F.Cu")
		(hatch none 0.5)
		(connect_pads
			(clearance 0)
		)
		(min_thickness 0.25)
		(keepout
			(tracks allowed)
			(vias allowed)
			(pads allowed)
			(copperpour allowed)
			(footprints allowed)
		)
		(placement
			(enabled no)
			(sheetname "")
		)
		(fill
			(thermal_gap 0.5)
			(thermal_bridge_width 0.5)
			(island_removal_mode 0)
		)
		(polygon
			(pts
				(xy 26.20391 -219.216478) (xy 26.20391 -218.77274) (xy 28.529026 -218.77274) (xy 28.529026 -219.216478)
			)
		)
	)
	(zone
		(layer "F.Cu")
		(hatch none 0.5)
		(connect_pads
			(clearance 0)
		)
		(min_thickness 0.25)
		(keepout
			(tracks allowed)
			(vias allowed)
			(pads allowed)
			(copperpour allowed)
			(footprints allowed)
		)
		(placement
			(enabled no)
			(sheetname "")
		)
		(fill
			(thermal_gap 0.5)
			(thermal_bridge_width 0.5)
			(island_removal_mode 0)
		)
		(polygon
			(pts
				(xy 289.231578 -285.516574) (xy 289.231578 -285.072836) (xy 291.556694 -285.072836) (xy 291.556694 -285.516574)
			)
		)
	)
	(zone
		(layer "F.Cu")
		(hatch none 0.5)
		(connect_pads
			(clearance 0)
		)
		(min_thickness 0.25)
		(keepout
			(tracks allowed)
			(vias allowed)
			(pads allowed)
			(copperpour allowed)
			(footprints allowed)
		)
		(placement
			(enabled no)
			(sheetname "")
		)
		(fill
			(thermal_gap 0.5)
			(thermal_bridge_width 0.5)
			(island_removal_mode 0)
		)
		(polygon
			(pts
				(xy 292.67531 -247.26646) (xy 292.67531 -246.822722) (xy 295.000426 -246.822722) (xy 295.000426 -247.26646)
			)
		)
	)
	(zone
		(layer "F.Cu")
		(hatch none 0.5)
		(connect_pads
			(clearance 0)
		)
		(min_thickness 0.25)
		(keepout
			(tracks allowed)
			(vias allowed)
			(pads allowed)
			(copperpour allowed)
			(footprints allowed)
		)
		(placement
			(enabled no)
			(sheetname "")
		)
		(fill
			(thermal_gap 0.5)
			(thermal_bridge_width 0.5)
			(island_removal_mode 0)
		)
		(polygon
			(pts
				(xy 139.656058 -257.96367) (xy 139.453112 -257.760724) (xy 139.409932 -257.760724) (xy 138.966194 -258.204462)
				(xy 138.966194 -258.326636) (xy 139.09929 -258.459478) (xy 139.20343 -258.459478) (xy 139.656058 -258.00685)
			)
		)
	)
	(zone
		(layer "F.Cu")
		(hatch none 0.5)
		(connect_pads
			(clearance 0)
		)
		(min_thickness 0.25)
		(keepout
			(tracks allowed)
			(vias allowed)
			(pads allowed)
			(copperpour allowed)
			(footprints allowed)
		)
		(placement
			(enabled no)
			(sheetname "")
		)
		(fill
			(thermal_gap 0.5)
			(thermal_bridge_width 0.5)
			(island_removal_mode 0)
		)
		(polygon
			(pts
				(xy 259.056378 -229.41661) (xy 259.056378 -228.972872) (xy 261.381494 -228.972872) (xy 261.381494 -229.41661)
			)
		)
	)
	(zone
		(layer "F.Cu")
		(hatch none 0.5)
		(connect_pads
			(clearance 0)
		)
		(min_thickness 0.25)
		(keepout
			(tracks allowed)
			(vias allowed)
			(pads allowed)
			(copperpour allowed)
			(footprints allowed)
		)
		(placement
			(enabled no)
			(sheetname "")
		)
		(fill
			(thermal_gap 0.5)
			(thermal_bridge_width 0.5)
			(island_removal_mode 0)
		)
		(polygon
			(pts
				(xy 165.335458 -301.554896) (xy 165.335458 -301.326296) (xy 167.367458 -301.326296) (xy 167.367458 -301.554896)
			)
		)
	)
	(zone
		(layer "F.Cu")
		(hatch none 0.5)
		(connect_pads
			(clearance 0)
		)
		(min_thickness 0.25)
		(keepout
			(tracks allowed)
			(vias allowed)
			(pads allowed)
			(copperpour allowed)
			(footprints allowed)
		)
		(placement
			(enabled no)
			(sheetname "")
		)
		(fill
			(thermal_gap 0.5)
			(thermal_bridge_width 0.5)
			(island_removal_mode 0)
		)
		(polygon
			(pts
				(xy 292.67531 -244.716554) (xy 292.67531 -244.272816) (xy 295.000426 -244.272816) (xy 295.000426 -244.716554)
			)
		)
	)
	(zone
		(layer "F.Cu")
		(hatch none 0.5)
		(connect_pads
			(clearance 0)
		)
		(min_thickness 0.25)
		(keepout
			(tracks allowed)
			(vias allowed)
			(pads allowed)
			(copperpour allowed)
			(footprints allowed)
		)
		(placement
			(enabled no)
			(sheetname "")
		)
		(fill
			(thermal_gap 0.5)
			(thermal_bridge_width 0.5)
			(island_removal_mode 0)
		)
		(polygon
			(pts
				(xy 161.891726 -211.455) (xy 161.891726 -211.2264) (xy 163.923726 -211.2264) (xy 163.923726 -211.455)
			)
		)
	)
	(zone
		(layer "F.Cu")
		(hatch none 0.5)
		(connect_pads
			(clearance 0)
		)
		(min_thickness 0.25)
		(keepout
			(tracks allowed)
			(vias allowed)
			(pads allowed)
			(copperpour allowed)
			(footprints allowed)
		)
		(placement
			(enabled no)
			(sheetname "")
		)
		(fill
			(thermal_gap 0.5)
			(thermal_bridge_width 0.5)
			(island_removal_mode 0)
		)
		(polygon
			(pts
				(xy 307.76291 -282.966414) (xy 307.76291 -282.522676) (xy 310.088026 -282.522676) (xy 310.088026 -282.966414)
			)
		)
	)
	(zone
		(layer "F.Cu")
		(hatch none 0.5)
		(connect_pads
			(clearance 0)
		)
		(min_thickness 0.25)
		(keepout
			(tracks allowed)
			(vias allowed)
			(pads allowed)
			(copperpour allowed)
			(footprints allowed)
		)
		(placement
			(enabled no)
			(sheetname "")
		)
		(fill
			(thermal_gap 0.5)
			(thermal_bridge_width 0.5)
			(island_removal_mode 0)
		)
		(polygon
			(pts
				(xy 385.26212 -219.278708) (xy 385.54914 -219.278708) (xy 385.57962 -219.248228) (xy 385.57962 -218.620848)
				(xy 385.49326 -218.534488) (xy 385.3053 -218.534488) (xy 385.23164 -218.608148) (xy 385.23164 -219.248228)
			)
		)
	)
	(zone
		(layer "F.Cu")
		(hatch none 0.5)
		(connect_pads
			(clearance 0)
		)
		(min_thickness 0.25)
		(keepout
			(tracks allowed)
			(vias allowed)
			(pads allowed)
			(copperpour allowed)
			(footprints allowed)
		)
		(placement
			(enabled no)
			(sheetname "")
		)
		(fill
			(thermal_gap 0.5)
			(thermal_bridge_width 0.5)
			(island_removal_mode 0)
		)
		(polygon
			(pts
				(xy 292.67531 -248.966482) (xy 292.67531 -248.522744) (xy 295.000426 -248.522744) (xy 295.000426 -248.966482)
			)
		)
	)
	(zone
		(layer "F.Cu")
		(hatch none 0.5)
		(connect_pads
			(clearance 0)
		)
		(min_thickness 0.25)
		(keepout
			(tracks allowed)
			(vias allowed)
			(pads allowed)
			(copperpour allowed)
			(footprints allowed)
		)
		(placement
			(enabled no)
			(sheetname "")
		)
		(fill
			(thermal_gap 0.5)
			(thermal_bridge_width 0.5)
			(island_removal_mode 0)
		)
		(polygon
			(pts
				(xy 413.275526 -199.554846) (xy 413.275526 -199.326246) (xy 415.307526 -199.326246) (xy 415.307526 -199.554846)
			)
		)
	)
	(zone
		(layer "F.Cu")
		(hatch none 0.5)
		(connect_pads
			(clearance 0)
		)
		(min_thickness 0.25)
		(keepout
			(tracks allowed)
			(vias allowed)
			(pads allowed)
			(copperpour allowed)
			(footprints allowed)
		)
		(placement
			(enabled no)
			(sheetname "")
		)
		(fill
			(thermal_gap 0.5)
			(thermal_bridge_width 0.5)
			(island_removal_mode 0)
		)
		(polygon
			(pts
				(xy 41.29151 -197.966584) (xy 41.29151 -197.522846) (xy 43.616626 -197.522846) (xy 43.616626 -197.966584)
			)
		)
	)
	(zone
		(layer "F.Cu")
		(hatch none 0.5)
		(connect_pads
			(clearance 0)
		)
		(min_thickness 0.25)
		(keepout
			(tracks allowed)
			(vias allowed)
			(pads allowed)
			(copperpour allowed)
			(footprints allowed)
		)
		(placement
			(enabled no)
			(sheetname "")
		)
		(fill
			(thermal_gap 0.5)
			(thermal_bridge_width 0.5)
			(island_removal_mode 0)
		)
		(polygon
			(pts
				(xy 59.822842 -281.266646) (xy 59.822842 -280.822908) (xy 62.147958 -280.822908) (xy 62.147958 -281.266646)
			)
		)
	)
	(zone
		(layer "F.Cu")
		(hatch none 0.5)
		(connect_pads
			(clearance 0)
		)
		(min_thickness 0.25)
		(keepout
			(tracks not_allowed)
			(vias allowed)
			(pads allowed)
			(copperpour not_allowed)
			(footprints allowed)
		)
		(placement
			(enabled no)
			(sheetname "")
		)
		(fill
			(thermal_gap 0.5)
			(thermal_bridge_width 0.5)
			(island_removal_mode 0)
		)
		(polygon
			(pts
				(xy 416.209988 -168.321736) (xy 415.960306 -168.321736) (xy 415.960306 -170.573446) (xy 416.01898 -170.63212)
				(xy 416.266122 -170.63212) (xy 416.266122 -170.769788) (xy 418.313362 -170.769788) (xy 418.313362 -172.623988)
				(xy 418.072316 -172.623988) (xy 418.072316 -172.866304) (xy 418.5539 -172.866304) (xy 418.5539 -168.91762)
				(xy 418.368988 -169.102532) (xy 418.368988 -170.47845) (xy 416.209988 -170.47845)
			)
		)
	)
	(zone
		(layer "F.Cu")
		(hatch none 0.5)
		(connect_pads
			(clearance 0)
		)
		(min_thickness 0.25)
		(keepout
			(tracks allowed)
			(vias allowed)
			(pads allowed)
			(copperpour allowed)
			(footprints not_allowed)
		)
		(placement
			(enabled no)
			(sheetname "")
		)
		(fill
			(thermal_gap 0.5)
			(thermal_bridge_width 0.5)
			(island_removal_mode 0)
		)
		(polygon
			(pts
				(xy 125.586998 -18.130012) (xy 195.22694 -18.130012)
				(arc
					(start 195.22694 -12.392406)
					(mid 194.111058 -11.292493)
					(end 193.701924 -9.780016)
				)
				(xy 193.701924 -6.279896) (xy 127.102108 -6.279896)
				(arc
					(start 127.102108 -9.780016)
					(mid 126.695747 -11.28742)
					(end 125.586998 -12.386564)
				)
			)
		)
	)
	(zone
		(layer "F.Cu")
		(hatch none 0.5)
		(connect_pads
			(clearance 0)
		)
		(min_thickness 0.25)
		(keepout
			(tracks allowed)
			(vias allowed)
			(pads allowed)
			(copperpour allowed)
			(footprints allowed)
		)
		(placement
			(enabled no)
			(sheetname "")
		)
		(fill
			(thermal_gap 0.5)
			(thermal_bridge_width 0.5)
			(island_removal_mode 0)
		)
		(polygon
			(pts
				(xy 289.231578 -297.416474) (xy 289.231578 -296.972736) (xy 291.556694 -296.972736) (xy 291.556694 -297.416474)
			)
		)
	)
	(zone
		(layer "F.Cu")
		(hatch none 0.5)
		(connect_pads
			(clearance 0)
		)
		(min_thickness 0.25)
		(keepout
			(tracks allowed)
			(vias allowed)
			(pads allowed)
			(copperpour allowed)
			(footprints allowed)
		)
		(placement
			(enabled no)
			(sheetname "")
		)
		(fill
			(thermal_gap 0.5)
			(thermal_bridge_width 0.5)
			(island_removal_mode 0)
		)
		(polygon
			(pts
				(xy 163.929568 -410.948886) (xy 163.929568 -406.105868) (xy 165.813994 -406.105868) (xy 165.813994 -410.948886)
			)
		)
	)
	(zone
		(layer "F.Cu")
		(hatch none 0.5)
		(connect_pads
			(clearance 0)
		)
		(min_thickness 0.25)
		(keepout
			(tracks allowed)
			(vias allowed)
			(pads allowed)
			(copperpour allowed)
			(footprints allowed)
		)
		(placement
			(enabled no)
			(sheetname "")
		)
		(fill
			(thermal_gap 0.5)
			(thermal_bridge_width 0.5)
			(island_removal_mode 0)
		)
		(polygon
			(pts
				(xy 59.822842 -248.966482) (xy 59.822842 -248.522744) (xy 62.147958 -248.522744) (xy 62.147958 -248.966482)
			)
		)
	)
	(zone
		(layer "F.Cu")
		(hatch none 0.5)
		(connect_pads
			(clearance 0)
		)
		(min_thickness 0.25)
		(keepout
			(tracks allowed)
			(vias allowed)
			(pads allowed)
			(copperpour allowed)
			(footprints allowed)
		)
		(placement
			(enabled no)
			(sheetname "")
		)
		(fill
			(thermal_gap 0.5)
			(thermal_bridge_width 0.5)
			(island_removal_mode 0)
		)
		(polygon
			(pts
				(xy 440.006994 -214.626444) (xy 442.038994 -214.626444) (xy 442.038994 -214.855044) (xy 440.006994 -214.855044)
				(xy 439.87085 -214.855044) (xy 439.82386 -214.855044) (xy 439.82386 -214.626444) (xy 439.87085 -214.626444)
			)
		)
	)
	(zone
		(layer "F.Cu")
		(hatch none 0.5)
		(connect_pads
			(clearance 0)
		)
		(min_thickness 0.25)
		(keepout
			(tracks allowed)
			(vias allowed)
			(pads allowed)
			(copperpour allowed)
			(footprints allowed)
		)
		(placement
			(enabled no)
			(sheetname "")
		)
		(fill
			(thermal_gap 0.5)
			(thermal_bridge_width 0.5)
			(island_removal_mode 0)
		)
		(polygon
			(pts
				(xy 458.538326 -207.204818) (xy 458.538326 -206.976218) (xy 460.570326 -206.976218) (xy 460.570326 -207.204818)
			)
		)
	)
	(zone
		(layer "F.Cu")
		(hatch none 0.5)
		(connect_pads
			(clearance 0)
		)
		(min_thickness 0.25)
		(keepout
			(tracks allowed)
			(vias allowed)
			(pads allowed)
			(copperpour allowed)
			(footprints allowed)
		)
		(placement
			(enabled no)
			(sheetname "")
		)
		(fill
			(thermal_gap 0.5)
			(thermal_bridge_width 0.5)
			(island_removal_mode 0)
		)
		(polygon
			(pts
				(xy 85.28812 -286.611568) (xy 85.57514 -286.611568) (xy 85.60562 -286.581088) (xy 85.60562 -285.953708)
				(xy 85.51926 -285.867348) (xy 85.3313 -285.867348) (xy 85.25764 -285.941008) (xy 85.25764 -286.581088)
			)
		)
	)
	(zone
		(layer "F.Cu")
		(hatch none 0.5)
		(connect_pads
			(clearance 0)
		)
		(min_thickness 0.25)
		(keepout
			(tracks allowed)
			(vias allowed)
			(pads allowed)
			(copperpour allowed)
			(footprints allowed)
		)
		(placement
			(enabled no)
			(sheetname "")
		)
		(fill
			(thermal_gap 0.5)
			(thermal_bridge_width 0.5)
			(island_removal_mode 0)
		)
		(polygon
			(pts
				(xy 24.47036 -181.600348) (xy 21.80336 -181.600348) (xy 20.93214 -181.600348) (xy 19.43354 -180.101748)
				(xy 19.43354 -178.227228) (xy 19.7104 -177.950368) (xy 20.53336 -177.950368) (xy 21.33092 -177.152808)
				(xy 25.54224 -177.152808) (xy 26.5176 -178.128168) (xy 26.5176 -179.885848) (xy 24.8031 -181.600348)
			)
		)
	)
	(zone
		(layer "F.Cu")
		(hatch none 0.5)
		(connect_pads
			(clearance 0)
		)
		(min_thickness 0.25)
		(keepout
			(tracks allowed)
			(vias allowed)
			(pads allowed)
			(copperpour allowed)
			(footprints allowed)
		)
		(placement
			(enabled no)
			(sheetname "")
		)
		(fill
			(thermal_gap 0.5)
			(thermal_bridge_width 0.5)
			(island_removal_mode 0)
		)
		(polygon
			(pts
				(xy 56.37911 -306.766468) (xy 56.37911 -306.32273) (xy 58.704226 -306.32273) (xy 58.704226 -306.766468)
			)
		)
	)
	(zone
		(layer "F.Cu")
		(hatch none 0.5)
		(connect_pads
			(clearance 0)
		)
		(min_thickness 0.25)
		(keepout
			(tracks allowed)
			(vias allowed)
			(pads allowed)
			(copperpour allowed)
			(footprints allowed)
		)
		(placement
			(enabled no)
			(sheetname "")
		)
		(fill
			(thermal_gap 0.5)
			(thermal_bridge_width 0.5)
			(island_removal_mode 0)
		)
		(polygon
			(pts
				(xy 11.11631 -210.716622) (xy 11.11631 -210.272884) (xy 13.441426 -210.272884) (xy 13.441426 -210.716622)
			)
		)
	)
	(zone
		(layer "F.Cu")
		(hatch none 0.5)
		(connect_pads
			(clearance 0)
		)
		(min_thickness 0.25)
		(keepout
			(tracks allowed)
			(vias allowed)
			(pads allowed)
			(copperpour allowed)
			(footprints allowed)
		)
		(placement
			(enabled no)
			(sheetname "")
		)
		(fill
			(thermal_gap 0.5)
			(thermal_bridge_width 0.5)
			(island_removal_mode 0)
		)
		(polygon
			(pts
				(xy 304.319178 -222.616522) (xy 304.319178 -222.172784) (xy 306.644294 -222.172784) (xy 306.644294 -222.616522)
			)
		)
	)
	(zone
		(layer "F.Cu")
		(hatch none 0.5)
		(connect_pads
			(clearance 0)
		)
		(min_thickness 0.25)
		(keepout
			(tracks allowed)
			(vias allowed)
			(pads allowed)
			(copperpour allowed)
			(footprints allowed)
		)
		(placement
			(enabled no)
			(sheetname "")
		)
		(fill
			(thermal_gap 0.5)
			(thermal_bridge_width 0.5)
			(island_removal_mode 0)
		)
		(polygon
			(pts
				(xy 455.094594 -287.726374) (xy 457.126594 -287.726374) (xy 457.126594 -287.954974) (xy 455.094594 -287.954974)
				(xy 454.95845 -287.954974) (xy 454.91146 -287.954974) (xy 454.91146 -287.726374) (xy 454.95845 -287.726374)
			)
		)
	)
	(zone
		(layer "F.Cu")
		(hatch none 0.5)
		(connect_pads
			(clearance 0)
		)
		(min_thickness 0.25)
		(keepout
			(tracks allowed)
			(vias allowed)
			(pads allowed)
			(copperpour allowed)
			(footprints allowed)
		)
		(placement
			(enabled no)
			(sheetname "")
		)
		(fill
			(thermal_gap 0.5)
			(thermal_bridge_width 0.5)
			(island_removal_mode 0)
		)
		(polygon
			(pts
				(xy 195.510658 -291.355018) (xy 195.510658 -291.126418) (xy 197.542658 -291.126418) (xy 197.542658 -291.355018)
			)
		)
	)
	(zone
		(layer "F.Cu")
		(hatch none 0.5)
		(connect_pads
			(clearance 0)
		)
		(min_thickness 0.25)
		(keepout
			(tracks allowed)
			(vias allowed)
			(pads allowed)
			(copperpour allowed)
			(footprints allowed)
		)
		(placement
			(enabled no)
			(sheetname "")
		)
		(fill
			(thermal_gap 0.5)
			(thermal_bridge_width 0.5)
			(island_removal_mode 0)
		)
		(polygon
			(pts
				(xy 370.318284 -360.717592) (xy 372.51132 -360.717592) (xy 372.87962 -360.349292) (xy 372.87962 -356.999032)
				(xy 370.20754 -354.326952) (xy 369.30584 -353.425252) (xy 366.054386 -353.425252) (xy 365.95304 -353.526598)
				(xy 365.95304 -354.377752) (xy 365.95304 -355.551232) (xy 366.04194 -355.640132) (xy 369.55984 -355.640132)
				(xy 369.64366 -355.723952) (xy 369.64366 -360.042968)
			)
		)
	)
	(zone
		(layer "F.Cu")
		(hatch none 0.5)
		(connect_pads
			(clearance 0)
		)
		(min_thickness 0.25)
		(keepout
			(tracks allowed)
			(vias allowed)
			(pads allowed)
			(copperpour allowed)
			(footprints allowed)
		)
		(placement
			(enabled no)
			(sheetname "")
		)
		(fill
			(thermal_gap 0.5)
			(thermal_bridge_width 0.5)
			(island_removal_mode 0)
		)
		(polygon
			(pts
				(xy 191.808862 -319.243202) (xy 191.808862 -316.881002) (xy 194.425062 -316.881002) (xy 194.425062 -319.243202)
			)
		)
	)
	(zone
		(layer "F.Cu")
		(hatch none 0.5)
		(connect_pads
			(clearance 0)
		)
		(min_thickness 0.25)
		(keepout
			(tracks allowed)
			(vias allowed)
			(pads allowed)
			(copperpour allowed)
			(footprints not_allowed)
		)
		(placement
			(enabled no)
			(sheetname "")
		)
		(fill
			(thermal_gap 0.5)
			(thermal_bridge_width 0.5)
			(island_removal_mode 0)
		)
		(polygon
			(pts
				(xy 168.361868 -87.278972) (xy 189.361826 -87.281258) (xy 189.36462 -59.981084) (xy 168.364662 -59.979052)
			)
		)
	)
	(zone
		(layer "F.Cu")
		(hatch none 0.5)
		(connect_pads
			(clearance 0)
		)
		(min_thickness 0.25)
		(keepout
			(tracks allowed)
			(vias allowed)
			(pads allowed)
			(copperpour allowed)
			(footprints allowed)
		)
		(placement
			(enabled no)
			(sheetname "")
		)
		(fill
			(thermal_gap 0.5)
			(thermal_bridge_width 0.5)
			(island_removal_mode 0)
		)
		(polygon
			(pts
				(xy 139.275058 -240.055146) (xy 139.478004 -239.8522) (xy 139.478004 -239.80902) (xy 139.034266 -239.365282)
				(xy 138.912092 -239.365282) (xy 138.77925 -239.498378) (xy 138.77925 -239.602518) (xy 139.231878 -240.055146)
			)
		)
	)
	(zone
		(layer "F.Cu")
		(hatch none 0.5)
		(connect_pads
			(clearance 0)
		)
		(min_thickness 0.25)
		(keepout
			(tracks allowed)
			(vias allowed)
			(pads allowed)
			(copperpour allowed)
			(footprints allowed)
		)
		(placement
			(enabled no)
			(sheetname "")
		)
		(fill
			(thermal_gap 0.5)
			(thermal_bridge_width 0.5)
			(island_removal_mode 0)
		)
		(polygon
			(pts
				(xy 113.946178 -413.92348) (xy 110.410498 -413.92348) (xy 110.410498 -411.84068) (xy 113.946178 -411.84068)
			)
		)
	)
	(zone
		(layer "F.Cu")
		(hatch none 0.5)
		(connect_pads
			(clearance 0)
		)
		(min_thickness 0.25)
		(keepout
			(tracks allowed)
			(vias allowed)
			(pads allowed)
			(copperpour allowed)
			(footprints allowed)
		)
		(placement
			(enabled no)
			(sheetname "")
		)
		(fill
			(thermal_gap 0.5)
			(thermal_bridge_width 0.5)
			(island_removal_mode 0)
		)
		(polygon
			(pts
				(xy 56.37911 -220.9165) (xy 56.37911 -220.472762) (xy 58.704226 -220.472762) (xy 58.704226 -220.9165)
			)
		)
	)
	(zone
		(layer "F.Cu")
		(hatch none 0.5)
		(connect_pads
			(clearance 0)
		)
		(min_thickness 0.25)
		(keepout
			(tracks allowed)
			(vias allowed)
			(pads allowed)
			(copperpour allowed)
			(footprints allowed)
		)
		(placement
			(enabled no)
			(sheetname "")
		)
		(fill
			(thermal_gap 0.5)
			(thermal_bridge_width 0.5)
			(island_removal_mode 0)
		)
		(polygon
			(pts
				(xy 41.29151 -285.516574) (xy 41.29151 -285.072836) (xy 43.616626 -285.072836) (xy 43.616626 -285.516574)
			)
		)
	)
	(zone
		(layer "F.Cu")
		(hatch none 0.5)
		(connect_pads
			(clearance 0)
		)
		(min_thickness 0.25)
		(keepout
			(tracks allowed)
			(vias allowed)
			(pads allowed)
			(copperpour allowed)
			(footprints allowed)
		)
		(placement
			(enabled no)
			(sheetname "")
		)
		(fill
			(thermal_gap 0.5)
			(thermal_bridge_width 0.5)
			(island_removal_mode 0)
		)
		(polygon
			(pts
				(xy 311.91708 -246.416576) (xy 311.91708 -245.972838) (xy 314.12688 -245.972838) (xy 314.12688 -246.416576)
			)
		)
	)
	(zone
		(layer "F.Cu")
		(hatch none 0.5)
		(connect_pads
			(clearance 0)
		)
		(min_thickness 0.25)
		(keepout
			(tracks allowed)
			(vias allowed)
			(pads allowed)
			(copperpour allowed)
			(footprints allowed)
		)
		(placement
			(enabled no)
			(sheetname "")
		)
		(fill
			(thermal_gap 0.5)
			(thermal_bridge_width 0.5)
			(island_removal_mode 0)
		)
		(polygon
			(pts
				(xy 56.37911 -270.622776) (xy 58.704226 -270.622776) (xy 58.757566 -270.622776) (xy 58.757566 -271.53362)
				(xy 56.256936 -271.53362) (xy 56.256936 -270.622776)
			)
		)
	)
	(zone
		(layer "F.Cu")
		(hatch none 0.5)
		(connect_pads
			(clearance 0)
		)
		(min_thickness 0.25)
		(keepout
			(tracks allowed)
			(vias allowed)
			(pads allowed)
			(copperpour allowed)
			(footprints allowed)
		)
		(placement
			(enabled no)
			(sheetname "")
		)
		(fill
			(thermal_gap 0.5)
			(thermal_bridge_width 0.5)
			(island_removal_mode 0)
		)
		(polygon
			(pts
				(xy 262.50011 -309.316628) (xy 262.50011 -308.87289) (xy 264.825226 -308.87289) (xy 264.825226 -309.316628)
			)
		)
	)
	(zone
		(layer "F.Cu")
		(hatch none 0.5)
		(connect_pads
			(clearance 0)
		)
		(min_thickness 0.25)
		(keepout
			(tracks allowed)
			(vias allowed)
			(pads allowed)
			(copperpour allowed)
			(footprints allowed)
		)
		(placement
			(enabled no)
			(sheetname "")
		)
		(fill
			(thermal_gap 0.5)
			(thermal_bridge_width 0.5)
			(island_removal_mode 0)
		)
		(polygon
			(pts
				(xy 259.056378 -239.616488) (xy 259.056378 -239.17275) (xy 261.381494 -239.17275) (xy 261.381494 -239.616488)
			)
		)
	)
	(zone
		(layer "F.Cu")
		(hatch none 0.5)
		(connect_pads
			(clearance 0)
		)
		(min_thickness 0.25)
		(keepout
			(tracks allowed)
			(vias allowed)
			(pads allowed)
			(copperpour allowed)
			(footprints allowed)
		)
		(placement
			(enabled no)
			(sheetname "")
		)
		(fill
			(thermal_gap 0.5)
			(thermal_bridge_width 0.5)
			(island_removal_mode 0)
		)
		(polygon
			(pts
				(xy 85.70976 -287.368488) (xy 85.99678 -287.368488) (xy 86.02726 -287.338008) (xy 86.02726 -286.710628)
				(xy 85.9409 -286.624268) (xy 85.75294 -286.624268) (xy 85.67928 -286.697928) (xy 85.67928 -287.338008)
			)
		)
	)
	(zone
		(layer "F.Cu")
		(hatch none 0.5)
		(connect_pads
			(clearance 0)
		)
		(min_thickness 0.25)
		(keepout
			(tracks allowed)
			(vias allowed)
			(pads allowed)
			(copperpour allowed)
			(footprints allowed)
		)
		(placement
			(enabled no)
			(sheetname "")
		)
		(fill
			(thermal_gap 0.5)
			(thermal_bridge_width 0.5)
			(island_removal_mode 0)
		)
		(polygon
			(pts
				(xy 455.094594 -211.2264) (xy 457.126594 -211.2264) (xy 457.126594 -211.455) (xy 455.094594 -211.455)
				(xy 454.95845 -211.455) (xy 454.91146 -211.455) (xy 454.91146 -211.2264) (xy 454.95845 -211.2264)
			)
		)
	)
	(zone
		(layer "F.Cu")
		(hatch none 0.5)
		(connect_pads
			(clearance 0)
		)
		(min_thickness 0.25)
		(keepout
			(tracks allowed)
			(vias allowed)
			(pads allowed)
			(copperpour allowed)
			(footprints not_allowed)
		)
		(placement
			(enabled no)
			(sheetname "")
		)
		(fill
			(thermal_gap 0.5)
			(thermal_bridge_width 0.5)
			(island_removal_mode 0)
		)
		(polygon
			(pts
				(xy 368.279934 -262.115046) (xy 368.279934 -236.514894) (xy 363.679994 -236.514894) (xy 363.679994 -262.115046)
			)
		)
	)
	(zone
		(layer "F.Cu")
		(hatch none 0.5)
		(connect_pads
			(clearance 0)
		)
		(min_thickness 0.25)
		(keepout
			(tracks allowed)
			(vias allowed)
			(pads allowed)
			(copperpour allowed)
			(footprints not_allowed)
		)
		(placement
			(enabled no)
			(sheetname "")
		)
		(fill
			(thermal_gap 0.5)
			(thermal_bridge_width 0.5)
			(island_removal_mode 0)
		)
		(polygon
			(pts
				(xy 255.08077 -330.091796) (xy 261.18058 -330.091796) (xy 261.18058 -186.09183) (xy 255.08077 -186.09183)
			)
		)
	)
	(zone
		(layer "F.Cu")
		(hatch none 0.5)
		(connect_pads
			(clearance 0)
		)
		(min_thickness 0.25)
		(keepout
			(tracks allowed)
			(vias allowed)
			(pads allowed)
			(copperpour allowed)
			(footprints allowed)
		)
		(placement
			(enabled no)
			(sheetname "")
		)
		(fill
			(thermal_gap 0.5)
			(thermal_bridge_width 0.5)
			(island_removal_mode 0)
		)
		(polygon
			(pts
				(xy 41.29151 -237.916466) (xy 41.29151 -237.472728) (xy 43.616626 -237.472728) (xy 43.616626 -237.916466)
			)
		)
	)
	(zone
		(layer "F.Cu")
		(hatch none 0.5)
		(connect_pads
			(clearance 0)
		)
		(min_thickness 0.25)
		(keepout
			(tracks allowed)
			(vias allowed)
			(pads allowed)
			(copperpour allowed)
			(footprints allowed)
		)
		(placement
			(enabled no)
			(sheetname "")
		)
		(fill
			(thermal_gap 0.5)
			(thermal_bridge_width 0.5)
			(island_removal_mode 0)
		)
		(polygon
			(pts
				(xy 176.979326 -247.776238) (xy 179.011326 -247.776238) (xy 179.011326 -248.004838) (xy 176.979326 -248.004838)
				(xy 176.812702 -248.004838) (xy 176.812702 -247.776238)
			)
		)
	)
	(zone
		(layer "F.Cu")
		(hatch none 0.5)
		(connect_pads
			(clearance 0)
		)
		(min_thickness 0.25)
		(keepout
			(tracks allowed)
			(vias allowed)
			(pads allowed)
			(copperpour allowed)
			(footprints allowed)
		)
		(placement
			(enabled no)
			(sheetname "")
		)
		(fill
			(thermal_gap 0.5)
			(thermal_bridge_width 0.5)
			(island_removal_mode 0)
		)
		(polygon
			(pts
				(xy 139.107418 -278.35987) (xy 138.904472 -278.156924) (xy 138.861292 -278.156924) (xy 138.417554 -278.600662)
				(xy 138.417554 -278.722836) (xy 138.55065 -278.855678) (xy 138.65479 -278.855678) (xy 139.107418 -278.40305)
			)
		)
	)
	(zone
		(layer "F.Cu")
		(hatch none 0.5)
		(connect_pads
			(clearance 0)
		)
		(min_thickness 0.25)
		(keepout
			(tracks allowed)
			(vias allowed)
			(pads allowed)
			(copperpour allowed)
			(footprints allowed)
		)
		(placement
			(enabled no)
			(sheetname "")
		)
		(fill
			(thermal_gap 0.5)
			(thermal_bridge_width 0.5)
			(island_removal_mode 0)
		)
		(polygon
			(pts
				(xy 304.319178 -251.516642) (xy 304.319178 -251.072904) (xy 306.644294 -251.072904) (xy 306.644294 -251.516642)
			)
		)
	)
	(zone
		(layer "F.Cu")
		(hatch none 0.5)
		(connect_pads
			(clearance 0)
		)
		(min_thickness 0.25)
		(keepout
			(tracks allowed)
			(vias allowed)
			(pads allowed)
			(copperpour allowed)
			(footprints allowed)
		)
		(placement
			(enabled no)
			(sheetname "")
		)
		(fill
			(thermal_gap 0.5)
			(thermal_bridge_width 0.5)
			(island_removal_mode 0)
		)
		(polygon
			(pts
				(xy 413.275526 -211.455) (xy 413.275526 -211.2264) (xy 415.307526 -211.2264) (xy 415.307526 -211.455)
			)
		)
	)
	(zone
		(layer "F.Cu")
		(hatch none 0.5)
		(connect_pads
			(clearance 0)
		)
		(min_thickness 0.25)
		(keepout
			(tracks allowed)
			(vias allowed)
			(pads allowed)
			(copperpour allowed)
			(footprints allowed)
		)
		(placement
			(enabled no)
			(sheetname "")
		)
		(fill
			(thermal_gap 0.5)
			(thermal_bridge_width 0.5)
			(island_removal_mode 0)
		)
		(polygon
			(pts
				(xy 274.143978 -313.566556) (xy 274.143978 -313.122818) (xy 276.469094 -313.122818) (xy 276.469094 -313.566556)
			)
		)
	)
	(zone
		(layer "F.Cu")
		(hatch none 0.5)
		(connect_pads
			(clearance 0)
		)
		(min_thickness 0.25)
		(keepout
			(tracks allowed)
			(vias allowed)
			(pads allowed)
			(copperpour allowed)
			(footprints allowed)
		)
		(placement
			(enabled no)
			(sheetname "")
		)
		(fill
			(thermal_gap 0.5)
			(thermal_bridge_width 0.5)
			(island_removal_mode 0)
		)
		(polygon
			(pts
				(xy 424.919394 -291.126418) (xy 426.951394 -291.126418) (xy 426.951394 -291.355018) (xy 424.919394 -291.355018)
				(xy 424.78325 -291.355018) (xy 424.73626 -291.355018) (xy 424.73626 -291.126418) (xy 424.78325 -291.126418)
			)
		)
	)
	(zone
		(layer "F.Cu")
		(hatch none 0.5)
		(connect_pads
			(clearance 0)
		)
		(min_thickness 0.25)
		(keepout
			(tracks allowed)
			(vias allowed)
			(pads allowed)
			(copperpour allowed)
			(footprints allowed)
		)
		(placement
			(enabled no)
			(sheetname "")
		)
		(fill
			(thermal_gap 0.5)
			(thermal_bridge_width 0.5)
			(island_removal_mode 0)
		)
		(polygon
			(pts
				(xy 289.231578 -288.06648) (xy 289.231578 -287.622742) (xy 291.556694 -287.622742) (xy 291.556694 -288.06648)
			)
		)
	)
	(zone
		(layer "F.Cu")
		(hatch none 0.5)
		(connect_pads
			(clearance 0)
		)
		(min_thickness 0.25)
		(keepout
			(tracks allowed)
			(vias allowed)
			(pads allowed)
			(copperpour allowed)
			(footprints allowed)
		)
		(placement
			(enabled no)
			(sheetname "")
		)
		(fill
			(thermal_gap 0.5)
			(thermal_bridge_width 0.5)
			(island_removal_mode 0)
		)
		(polygon
			(pts
				(xy 59.822842 -309.316628) (xy 59.822842 -308.87289) (xy 62.147958 -308.87289) (xy 62.147958 -309.316628)
			)
		)
	)
	(zone
		(layer "F.Cu")
		(hatch none 0.5)
		(connect_pads
			(clearance 0)
		)
		(min_thickness 0.25)
		(keepout
			(tracks allowed)
			(vias allowed)
			(pads allowed)
			(copperpour allowed)
			(footprints allowed)
		)
		(placement
			(enabled no)
			(sheetname "")
		)
		(fill
			(thermal_gap 0.5)
			(thermal_bridge_width 0.5)
			(island_removal_mode 0)
		)
		(polygon
			(pts
				(xy 262.50011 -224.316544) (xy 262.50011 -223.872806) (xy 264.825226 -223.872806) (xy 264.825226 -224.316544)
			)
		)
	)
	(zone
		(layer "F.Cu")
		(hatch none 0.5)
		(connect_pads
			(clearance 0)
		)
		(min_thickness 0.25)
		(keepout
			(tracks allowed)
			(vias allowed)
			(pads allowed)
			(copperpour allowed)
			(footprints allowed)
		)
		(placement
			(enabled no)
			(sheetname "")
		)
		(fill
			(thermal_gap 0.5)
			(thermal_bridge_width 0.5)
			(island_removal_mode 0)
		)
		(polygon
			(pts
				(xy 181.704234 -355.797104) (xy 179.956714 -355.797104) (xy 179.956714 -353.861624) (xy 181.704234 -353.861624)
			)
		)
	)
	(zone
		(layer "F.Cu")
		(hatch none 0.5)
		(connect_pads
			(clearance 0)
		)
		(min_thickness 0.25)
		(keepout
			(tracks allowed)
			(vias allowed)
			(pads allowed)
			(copperpour allowed)
			(footprints allowed)
		)
		(placement
			(enabled no)
			(sheetname "")
		)
		(fill
			(thermal_gap 0.5)
			(thermal_bridge_width 0.5)
			(island_removal_mode 0)
		)
		(polygon
			(pts
				(xy 262.50011 -218.366594) (xy 262.50011 -217.922856) (xy 264.825226 -217.922856) (xy 264.825226 -218.366594)
			)
		)
	)
	(zone
		(layer "F.Cu")
		(hatch none 0.5)
		(connect_pads
			(clearance 0)
		)
		(min_thickness 0.25)
		(keepout
			(tracks allowed)
			(vias allowed)
			(pads allowed)
			(copperpour allowed)
			(footprints allowed)
		)
		(placement
			(enabled no)
			(sheetname "")
		)
		(fill
			(thermal_gap 0.5)
			(thermal_bridge_width 0.5)
			(island_removal_mode 0)
		)
		(polygon
			(pts
				(xy 207.154526 -278.37638) (xy 209.186526 -278.37638) (xy 209.186526 -278.60498) (xy 207.154526 -278.60498)
				(xy 207.018382 -278.60498) (xy 206.971392 -278.60498) (xy 206.971392 -278.37638) (xy 207.018382 -278.37638)
			)
		)
	)
	(zone
		(layer "F.Cu")
		(hatch none 0.5)
		(connect_pads
			(clearance 0)
		)
		(min_thickness 0.25)
		(keepout
			(tracks allowed)
			(vias allowed)
			(pads allowed)
			(copperpour allowed)
			(footprints allowed)
		)
		(placement
			(enabled no)
			(sheetname "")
		)
		(fill
			(thermal_gap 0.5)
			(thermal_bridge_width 0.5)
			(island_removal_mode 0)
		)
		(polygon
			(pts
				(xy 458.538326 -297.304968) (xy 458.538326 -297.076368) (xy 460.570326 -297.076368) (xy 460.570326 -297.304968)
			)
		)
	)
	(zone
		(layer "F.Cu")
		(hatch none 0.5)
		(connect_pads
			(clearance 0)
		)
		(min_thickness 0.25)
		(keepout
			(tracks allowed)
			(vias allowed)
			(pads allowed)
			(copperpour allowed)
			(footprints allowed)
		)
		(placement
			(enabled no)
			(sheetname "")
		)
		(fill
			(thermal_gap 0.5)
			(thermal_bridge_width 0.5)
			(island_removal_mode 0)
		)
		(polygon
			(pts
				(xy 195.510658 -302.405034) (xy 195.510658 -302.176434) (xy 197.542658 -302.176434) (xy 197.542658 -302.405034)
			)
		)
	)
	(zone
		(layer "F.Cu")
		(hatch none 0.5)
		(connect_pads
			(clearance 0)
		)
		(min_thickness 0.25)
		(keepout
			(tracks allowed)
			(vias allowed)
			(pads allowed)
			(copperpour allowed)
			(footprints allowed)
		)
		(placement
			(enabled no)
			(sheetname "")
		)
		(fill
			(thermal_gap 0.5)
			(thermal_bridge_width 0.5)
			(island_removal_mode 0)
		)
		(polygon
			(pts
				(xy 176.979326 -240.976404) (xy 179.011326 -240.976404) (xy 179.011326 -241.205004) (xy 176.979326 -241.205004)
				(xy 176.843182 -241.205004) (xy 176.796192 -241.205004) (xy 176.796192 -240.976404) (xy 176.843182 -240.976404)
			)
		)
	)
	(zone
		(layer "F.Cu")
		(hatch none 0.5)
		(connect_pads
			(clearance 0)
		)
		(min_thickness 0.25)
		(keepout
			(tracks allowed)
			(vias allowed)
			(pads allowed)
			(copperpour allowed)
			(footprints allowed)
		)
		(placement
			(enabled no)
			(sheetname "")
		)
		(fill
			(thermal_gap 0.5)
			(thermal_bridge_width 0.5)
			(island_removal_mode 0)
		)
		(polygon
			(pts
				(xy 59.822842 -220.9165) (xy 59.822842 -220.472762) (xy 62.147958 -220.472762) (xy 62.147958 -220.9165)
			)
		)
	)
	(zone
		(layer "F.Cu")
		(hatch none 0.5)
		(connect_pads
			(clearance 0)
		)
		(min_thickness 0.25)
		(keepout
			(tracks allowed)
			(vias allowed)
			(pads allowed)
			(copperpour allowed)
			(footprints allowed)
		)
		(placement
			(enabled no)
			(sheetname "")
		)
		(fill
			(thermal_gap 0.5)
			(thermal_bridge_width 0.5)
			(island_removal_mode 0)
		)
		(polygon
			(pts
				(xy 292.67531 -224.316544) (xy 292.67531 -223.872806) (xy 295.000426 -223.872806) (xy 295.000426 -224.316544)
			)
		)
	)
	(zone
		(layer "F.Cu")
		(hatch none 0.5)
		(connect_pads
			(clearance 0)
		)
		(min_thickness 0.25)
		(keepout
			(tracks allowed)
			(vias allowed)
			(pads allowed)
			(copperpour allowed)
			(footprints allowed)
		)
		(placement
			(enabled no)
			(sheetname "")
		)
		(fill
			(thermal_gap 0.5)
			(thermal_bridge_width 0.5)
			(island_removal_mode 0)
		)
		(polygon
			(pts
				(xy 161.891726 -222.505016) (xy 161.891726 -222.276416) (xy 163.923726 -222.276416) (xy 163.923726 -222.505016)
			)
		)
	)
	(zone
		(layer "F.Cu")
		(hatch none 0.5)
		(connect_pads
			(clearance 0)
		)
		(min_thickness 0.25)
		(keepout
			(tracks allowed)
			(vias allowed)
			(pads allowed)
			(copperpour allowed)
			(footprints allowed)
		)
		(placement
			(enabled no)
			(sheetname "")
		)
		(fill
			(thermal_gap 0.5)
			(thermal_bridge_width 0.5)
			(island_removal_mode 0)
		)
		(polygon
			(pts
				(xy 161.891726 -314.304934) (xy 161.891726 -314.076334) (xy 163.923726 -314.076334) (xy 163.923726 -314.304934)
			)
		)
	)
	(zone
		(layer "F.Cu")
		(hatch none 0.5)
		(connect_pads
			(clearance 0)
		)
		(min_thickness 0.25)
		(keepout
			(tracks allowed)
			(vias allowed)
			(pads allowed)
			(copperpour allowed)
			(footprints allowed)
		)
		(placement
			(enabled no)
			(sheetname "")
		)
		(fill
			(thermal_gap 0.5)
			(thermal_bridge_width 0.5)
			(island_removal_mode 0)
		)
		(polygon
			(pts
				(xy 409.831794 -274.976336) (xy 411.863794 -274.976336) (xy 411.863794 -274.978622) (xy 412.017464 -274.978622)
				(xy 412.017464 -275.768562) (xy 409.610814 -275.768562) (xy 409.350972 -275.768562) (xy 409.344368 -275.768562)
				(xy 409.344368 -275.291804) (xy 409.468574 -275.291804) (xy 409.468574 -274.976336) (xy 409.507182 -274.976336)
				(xy 409.551124 -274.976336) (xy 409.64866 -274.976336) (xy 409.69565 -274.976336)
			)
		)
	)
	(zone
		(layer "F.Cu")
		(hatch none 0.5)
		(connect_pads
			(clearance 0)
		)
		(min_thickness 0.25)
		(keepout
			(tracks allowed)
			(vias allowed)
			(pads allowed)
			(copperpour allowed)
			(footprints allowed)
		)
		(placement
			(enabled no)
			(sheetname "")
		)
		(fill
			(thermal_gap 0.5)
			(thermal_bridge_width 0.5)
			(island_removal_mode 0)
		)
		(polygon
			(pts
				(xy 192.066926 -228.456998) (xy 194.098926 -228.456998) (xy 194.098926 -228.228398) (xy 192.066926 -228.228398)
				(xy 191.935608 -228.228398) (xy 191.9097 -228.228398) (xy 191.9097 -228.456998) (xy 191.935608 -228.456998)
			)
		)
	)
	(zone
		(layer "F.Cu")
		(hatch none 0.5)
		(connect_pads
			(clearance 0)
		)
		(min_thickness 0.25)
		(keepout
			(tracks allowed)
			(vias allowed)
			(pads allowed)
			(copperpour allowed)
			(footprints not_allowed)
		)
		(placement
			(enabled no)
			(sheetname "")
		)
		(fill
			(thermal_gap 0.5)
			(thermal_bridge_width 0.5)
			(island_removal_mode 0)
		)
		(polygon
			(pts
				(xy 22.228302 -330.091796) (xy 28.328112 -330.091796) (xy 28.328112 -186.09183) (xy 22.228302 -186.09183)
			)
		)
	)
	(zone
		(layer "F.Cu")
		(hatch none 0.5)
		(connect_pads
			(clearance 0)
		)
		(min_thickness 0.25)
		(keepout
			(tracks allowed)
			(vias allowed)
			(pads allowed)
			(copperpour allowed)
			(footprints allowed)
		)
		(placement
			(enabled no)
			(sheetname "")
		)
		(fill
			(thermal_gap 0.5)
			(thermal_bridge_width 0.5)
			(island_removal_mode 0)
		)
		(polygon
			(pts
				(xy 132.27812 -336.996786) (xy 128.74244 -336.996786) (xy 128.74244 -334.913986) (xy 132.27812 -334.913986)
			)
		)
	)
	(zone
		(layer "F.Cu")
		(hatch none 0.5)
		(connect_pads
			(clearance 0)
		)
		(min_thickness 0.25)
		(keepout
			(tracks allowed)
			(vias allowed)
			(pads allowed)
			(copperpour allowed)
			(footprints allowed)
		)
		(placement
			(enabled no)
			(sheetname "")
		)
		(fill
			(thermal_gap 0.5)
			(thermal_bridge_width 0.5)
			(island_removal_mode 0)
		)
		(polygon
			(pts
				(xy 277.58771 -290.61664) (xy 277.58771 -290.172902) (xy 279.912826 -290.172902) (xy 279.912826 -290.61664)
			)
		)
	)
	(zone
		(layer "F.Cu")
		(hatch none 0.5)
		(connect_pads
			(clearance 0)
		)
		(min_thickness 0.25)
		(keepout
			(tracks allowed)
			(vias allowed)
			(pads allowed)
			(copperpour allowed)
			(footprints allowed)
		)
		(placement
			(enabled no)
			(sheetname "")
		)
		(fill
			(thermal_gap 0.5)
			(thermal_bridge_width 0.5)
			(island_removal_mode 0)
		)
		(polygon
			(pts
				(xy 401.832064 -5.888228) (xy 401.832064 -3.952748) (xy 404.003764 -3.952748) (xy 404.003764 -5.888228)
			)
		)
	)
	(zone
		(layer "F.Cu")
		(hatch none 0.5)
		(connect_pads
			(clearance 0)
		)
		(min_thickness 0.25)
		(keepout
			(tracks allowed)
			(vias allowed)
			(pads allowed)
			(copperpour allowed)
			(footprints allowed)
		)
		(placement
			(enabled no)
			(sheetname "")
		)
		(fill
			(thermal_gap 0.5)
			(thermal_bridge_width 0.5)
			(island_removal_mode 0)
		)
		(polygon
			(pts
				(xy 384.89128 -286.588708) (xy 385.1783 -286.588708) (xy 385.20878 -286.558228) (xy 385.20878 -285.930848)
				(xy 385.12242 -285.844488) (xy 384.93446 -285.844488) (xy 384.8608 -285.918148) (xy 384.8608 -286.558228)
			)
		)
	)
	(zone
		(layer "F.Cu")
		(hatch none 0.5)
		(connect_pads
			(clearance 0)
		)
		(min_thickness 0.25)
		(keepout
			(tracks allowed)
			(vias allowed)
			(pads allowed)
			(copperpour allowed)
			(footprints allowed)
		)
		(placement
			(enabled no)
			(sheetname "")
		)
		(fill
			(thermal_gap 0.5)
			(thermal_bridge_width 0.5)
			(island_removal_mode 0)
		)
		(polygon
			(pts
				(xy 259.056378 -289.766502) (xy 259.056378 -289.322764) (xy 261.381494 -289.322764) (xy 261.381494 -289.766502)
			)
		)
	)
	(zone
		(layer "F.Cu")
		(hatch none 0.5)
		(connect_pads
			(clearance 0)
		)
		(min_thickness 0.25)
		(keepout
			(tracks allowed)
			(vias allowed)
			(pads allowed)
			(copperpour allowed)
			(footprints allowed)
		)
		(placement
			(enabled no)
			(sheetname "")
		)
		(fill
			(thermal_gap 0.5)
			(thermal_bridge_width 0.5)
			(island_removal_mode 0)
		)
		(polygon
			(pts
				(xy 304.319178 -276.912832) (xy 304.319178 -276.572726) (xy 306.644294 -276.572726) (xy 306.698396 -276.572726)
				(xy 306.698396 -277.51278) (xy 304.193702 -277.51278) (xy 304.193702 -276.912832)
			)
		)
	)
	(zone
		(layer "F.Cu")
		(hatch none 0.5)
		(connect_pads
			(clearance 0)
		)
		(min_thickness 0.25)
		(keepout
			(tracks allowed)
			(vias allowed)
			(pads allowed)
			(copperpour allowed)
			(footprints allowed)
		)
		(placement
			(enabled no)
			(sheetname "")
		)
		(fill
			(thermal_gap 0.5)
			(thermal_bridge_width 0.5)
			(island_removal_mode 0)
		)
		(polygon
			(pts
				(xy 289.231578 -222.616522) (xy 289.231578 -222.172784) (xy 291.556694 -222.172784) (xy 291.556694 -222.616522)
			)
		)
	)
	(zone
		(layer "F.Cu")
		(hatch none 0.5)
		(connect_pads
			(clearance 0)
		)
		(min_thickness 0.25)
		(keepout
			(tracks allowed)
			(vias allowed)
			(pads allowed)
			(copperpour allowed)
			(footprints allowed)
		)
		(placement
			(enabled no)
			(sheetname "")
		)
		(fill
			(thermal_gap 0.5)
			(thermal_bridge_width 0.5)
			(island_removal_mode 0)
		)
		(polygon
			(pts
				(xy 192.066926 -206.976472) (xy 194.098926 -206.976472) (xy 194.098926 -207.205072) (xy 192.066926 -207.205072)
				(xy 191.930782 -207.205072) (xy 191.883792 -207.205072) (xy 191.883792 -206.976472) (xy 191.930782 -206.976472)
			)
		)
	)
	(zone
		(layer "F.Cu")
		(hatch none 0.5)
		(connect_pads
			(clearance 0)
		)
		(min_thickness 0.25)
		(keepout
			(tracks allowed)
			(vias allowed)
			(pads allowed)
			(copperpour allowed)
			(footprints allowed)
		)
		(placement
			(enabled no)
			(sheetname "")
		)
		(fill
			(thermal_gap 0.5)
			(thermal_bridge_width 0.5)
			(island_removal_mode 0)
		)
		(polygon
			(pts
				(xy 443.450726 -225.904806) (xy 443.450726 -225.676206) (xy 445.482726 -225.676206) (xy 445.482726 -225.904806)
			)
		)
	)
	(zone
		(layer "F.Cu")
		(hatch none 0.5)
		(connect_pads
			(clearance 0)
		)
		(min_thickness 0.25)
		(keepout
			(tracks allowed)
			(vias allowed)
			(pads allowed)
			(copperpour allowed)
			(footprints allowed)
		)
		(placement
			(enabled no)
			(sheetname "")
		)
		(fill
			(thermal_gap 0.5)
			(thermal_bridge_width 0.5)
			(island_removal_mode 0)
		)
		(polygon
			(pts
				(xy 458.538326 -231.85501) (xy 458.538326 -231.62641) (xy 460.570326 -231.62641) (xy 460.570326 -231.85501)
			)
		)
	)
	(zone
		(layer "F.Cu")
		(hatch none 0.5)
		(connect_pads
			(clearance 0)
		)
		(min_thickness 0.25)
		(keepout
			(tracks allowed)
			(vias allowed)
			(pads allowed)
			(copperpour allowed)
			(footprints allowed)
		)
		(placement
			(enabled no)
			(sheetname "")
		)
		(fill
			(thermal_gap 0.5)
			(thermal_bridge_width 0.5)
			(island_removal_mode 0)
		)
		(polygon
			(pts
				(xy 195.510658 -202.105006) (xy 195.510658 -201.876406) (xy 197.542658 -201.876406) (xy 197.542658 -202.105006)
			)
		)
	)
	(zone
		(layer "F.Cu")
		(hatch none 0.5)
		(connect_pads
			(clearance 0)
		)
		(min_thickness 0.25)
		(keepout
			(tracks allowed)
			(vias allowed)
			(pads allowed)
			(copperpour allowed)
			(footprints allowed)
		)
		(placement
			(enabled no)
			(sheetname "")
		)
		(fill
			(thermal_gap 0.5)
			(thermal_bridge_width 0.5)
			(island_removal_mode 0)
		)
		(polygon
			(pts
				(xy 292.67531 -212.416644) (xy 292.67531 -211.972906) (xy 295.000426 -211.972906) (xy 295.000426 -212.416644)
			)
		)
	)
	(zone
		(layer "F.Cu")
		(hatch none 0.5)
		(connect_pads
			(clearance 0)
		)
		(min_thickness 0.25)
		(keepout
			(tracks allowed)
			(vias allowed)
			(pads allowed)
			(copperpour allowed)
			(footprints allowed)
		)
		(placement
			(enabled no)
			(sheetname "")
		)
		(fill
			(thermal_gap 0.5)
			(thermal_bridge_width 0.5)
			(island_removal_mode 0)
		)
		(polygon
			(pts
				(xy 445.493902 -276.90699) (xy 443.461902 -276.90699) (xy 443.461902 -276.904704) (xy 443.283086 -276.904704)
				(xy 443.283086 -276.667468) (xy 443.145164 -276.667468) (xy 443.101984 -276.624288) (xy 443.101984 -276.491446)
				(xy 443.101984 -276.187408) (xy 443.174628 -276.114764) (xy 445.714882 -276.114764) (xy 445.856106 -276.255988)
				(xy 445.856106 -276.453092) (xy 445.774572 -276.534626) (xy 445.774572 -276.90699) (xy 445.677036 -276.90699)
				(xy 445.630046 -276.90699)
			)
		)
	)
	(zone
		(layer "F.Cu")
		(hatch none 0.5)
		(connect_pads
			(clearance 0)
		)
		(min_thickness 0.25)
		(keepout
			(tracks allowed)
			(vias allowed)
			(pads allowed)
			(copperpour allowed)
			(footprints allowed)
		)
		(placement
			(enabled no)
			(sheetname "")
		)
		(fill
			(thermal_gap 0.5)
			(thermal_bridge_width 0.5)
			(island_removal_mode 0)
		)
		(polygon
			(pts
				(xy 138.35888 -285.775908) (xy 138.6459 -285.775908) (xy 138.67638 -285.745428) (xy 138.67638 -285.118048)
				(xy 138.59002 -285.031688) (xy 138.40206 -285.031688) (xy 138.3284 -285.105348) (xy 138.3284 -285.745428)
			)
		)
	)
	(zone
		(layer "F.Cu")
		(hatch none 0.5)
		(connect_pads
			(clearance 0)
		)
		(min_thickness 0.25)
		(keepout
			(tracks allowed)
			(vias allowed)
			(pads allowed)
			(copperpour allowed)
			(footprints allowed)
		)
		(placement
			(enabled no)
			(sheetname "")
		)
		(fill
			(thermal_gap 0.5)
			(thermal_bridge_width 0.5)
			(island_removal_mode 0)
		)
		(polygon
			(pts
				(xy 335.501742 -410.948886) (xy 335.501742 -406.105868) (xy 337.386168 -406.105868) (xy 337.386168 -410.948886)
			)
		)
	)
	(zone
		(layer "F.Cu")
		(hatch none 0.5)
		(connect_pads
			(clearance 0)
		)
		(min_thickness 0.25)
		(keepout
			(tracks allowed)
			(vias allowed)
			(pads allowed)
			(copperpour allowed)
			(footprints allowed)
		)
		(placement
			(enabled no)
			(sheetname "")
		)
		(fill
			(thermal_gap 0.5)
			(thermal_bridge_width 0.5)
			(island_removal_mode 0)
		)
		(polygon
			(pts
				(xy 44.735242 -221.766638) (xy 44.735242 -221.3229) (xy 47.060358 -221.3229) (xy 47.060358 -221.766638)
			)
		)
	)
	(zone
		(layer "F.Cu")
		(hatch none 0.5)
		(connect_pads
			(clearance 0)
		)
		(min_thickness 0.25)
		(keepout
			(tracks allowed)
			(vias allowed)
			(pads allowed)
			(copperpour allowed)
			(footprints allowed)
		)
		(placement
			(enabled no)
			(sheetname "")
		)
		(fill
			(thermal_gap 0.5)
			(thermal_bridge_width 0.5)
			(island_removal_mode 0)
		)
		(polygon
			(pts
				(xy 26.20391 -201.366628) (xy 26.20391 -200.92289) (xy 28.529026 -200.92289) (xy 28.529026 -201.366628)
			)
		)
	)
	(zone
		(layer "F.Cu")
		(hatch none 0.5)
		(connect_pads
			(clearance 0)
		)
		(min_thickness 0.25)
		(keepout
			(tracks allowed)
			(vias allowed)
			(pads allowed)
			(copperpour allowed)
			(footprints allowed)
		)
		(placement
			(enabled no)
			(sheetname "")
		)
		(fill
			(thermal_gap 0.5)
			(thermal_bridge_width 0.5)
			(island_removal_mode 0)
		)
		(polygon
			(pts
				(xy 311.96788 -211.566506) (xy 311.96788 -211.122768) (xy 314.10148 -211.122768) (xy 314.10148 -211.566506)
			)
		)
	)
	(zone
		(layer "F.Cu")
		(hatch none 0.5)
		(connect_pads
			(clearance 0)
		)
		(min_thickness 0.25)
		(keepout
			(tracks allowed)
			(vias allowed)
			(pads allowed)
			(copperpour allowed)
			(footprints allowed)
		)
		(placement
			(enabled no)
			(sheetname "")
		)
		(fill
			(thermal_gap 0.5)
			(thermal_bridge_width 0.5)
			(island_removal_mode 0)
		)
		(polygon
			(pts
				(xy 274.143978 -247.26646) (xy 274.143978 -246.822722) (xy 276.469094 -246.822722) (xy 276.469094 -247.26646)
			)
		)
	)
	(zone
		(layer "F.Cu")
		(hatch none 0.5)
		(connect_pads
			(clearance 0)
		)
		(min_thickness 0.25)
		(keepout
			(tracks allowed)
			(vias allowed)
			(pads allowed)
			(copperpour allowed)
			(footprints allowed)
		)
		(placement
			(enabled no)
			(sheetname "")
		)
		(fill
			(thermal_gap 0.5)
			(thermal_bridge_width 0.5)
			(island_removal_mode 0)
		)
		(polygon
			(pts
				(xy 56.37911 -233.2228) (xy 58.704226 -233.2228) (xy 58.768234 -233.2228) (xy 58.768234 -234.137962)
				(xy 56.245506 -234.137962) (xy 56.245506 -233.2228)
			)
		)
	)
	(zone
		(layer "F.Cu")
		(hatch none 0.5)
		(connect_pads
			(clearance 0)
		)
		(min_thickness 0.25)
		(keepout
			(tracks allowed)
			(vias allowed)
			(pads allowed)
			(copperpour allowed)
			(footprints allowed)
		)
		(placement
			(enabled no)
			(sheetname "")
		)
		(fill
			(thermal_gap 0.5)
			(thermal_bridge_width 0.5)
			(island_removal_mode 0)
		)
		(polygon
			(pts
				(xy 41.29151 -272.766536) (xy 41.29151 -272.322798) (xy 43.616626 -272.322798) (xy 43.616626 -272.766536)
			)
		)
	)
	(zone
		(layer "F.Cu")
		(hatch none 0.5)
		(connect_pads
			(clearance 0)
		)
		(min_thickness 0.25)
		(keepout
			(tracks allowed)
			(vias allowed)
			(pads allowed)
			(copperpour allowed)
			(footprints allowed)
		)
		(placement
			(enabled no)
			(sheetname "")
		)
		(fill
			(thermal_gap 0.5)
			(thermal_bridge_width 0.5)
			(island_removal_mode 0)
		)
		(polygon
			(pts
				(xy 180.10124 -48.336708) (xy 180.10124 -46.741588) (xy 183.06796 -46.741588) (xy 183.06796 -48.336708)
			)
		)
	)
	(zone
		(layer "F.Cu")
		(hatch none 0.5)
		(connect_pads
			(clearance 0)
		)
		(min_thickness 0.25)
		(keepout
			(tracks allowed)
			(vias allowed)
			(pads allowed)
			(copperpour allowed)
			(footprints allowed)
		)
		(placement
			(enabled no)
			(sheetname "")
		)
		(fill
			(thermal_gap 0.5)
			(thermal_bridge_width 0.5)
			(island_removal_mode 0)
		)
		(polygon
			(pts
				(xy 428.363126 -248.854976) (xy 428.363126 -248.626376) (xy 430.395126 -248.626376) (xy 430.395126 -248.854976)
			)
		)
	)
	(zone
		(layer "F.Cu")
		(hatch none 0.5)
		(connect_pads
			(clearance 0)
		)
		(min_thickness 0.25)
		(keepout
			(tracks not_allowed)
			(vias allowed)
			(pads allowed)
			(copperpour not_allowed)
			(footprints allowed)
		)
		(placement
			(enabled no)
			(sheetname "")
		)
		(fill
			(thermal_gap 0.5)
			(thermal_bridge_width 0.5)
			(island_removal_mode 0)
		)
		(polygon
			(pts
				(xy 38.38702 -393.92098) (xy 38.38702 -392.35634) (xy 38.61308 -392.35634) (xy 38.61308 -393.92098)
			)
		)
	)
	(zone
		(layer "F.Cu")
		(hatch none 0.5)
		(connect_pads
			(clearance 0)
		)
		(min_thickness 0.25)
		(keepout
			(tracks allowed)
			(vias allowed)
			(pads allowed)
			(copperpour allowed)
			(footprints allowed)
		)
		(placement
			(enabled no)
			(sheetname "")
		)
		(fill
			(thermal_gap 0.5)
			(thermal_bridge_width 0.5)
			(island_removal_mode 0)
		)
		(polygon
			(pts
				(xy 180.423058 -295.604946) (xy 180.423058 -295.376346) (xy 182.455058 -295.376346) (xy 182.455058 -295.604946)
			)
		)
	)
	(zone
		(layer "F.Cu")
		(hatch none 0.5)
		(connect_pads
			(clearance 0)
		)
		(min_thickness 0.25)
		(keepout
			(tracks allowed)
			(vias allowed)
			(pads allowed)
			(copperpour allowed)
			(footprints allowed)
		)
		(placement
			(enabled no)
			(sheetname "")
		)
		(fill
			(thermal_gap 0.5)
			(thermal_bridge_width 0.5)
			(island_removal_mode 0)
		)
		(polygon
			(pts
				(xy 409.831794 -251.404882) (xy 409.831794 -251.176282) (xy 411.863794 -251.176282) (xy 411.863794 -251.404882)
			)
		)
	)
	(zone
		(layer "F.Cu")
		(hatch none 0.5)
		(connect_pads
			(clearance 0)
		)
		(min_thickness 0.25)
		(keepout
			(tracks allowed)
			(vias allowed)
			(pads allowed)
			(copperpour allowed)
			(footprints allowed)
		)
		(placement
			(enabled no)
			(sheetname "")
		)
		(fill
			(thermal_gap 0.5)
			(thermal_bridge_width 0.5)
			(island_removal_mode 0)
		)
		(polygon
			(pts
				(xy 424.919394 -249.47626) (xy 426.951394 -249.47626) (xy 426.951394 -249.70486) (xy 424.919394 -249.70486)
				(xy 424.75277 -249.70486) (xy 424.75277 -249.47626)
			)
		)
	)
	(zone
		(layer "F.Cu")
		(hatch none 0.5)
		(connect_pads
			(clearance 0)
		)
		(min_thickness 0.25)
		(keepout
			(tracks allowed)
			(vias allowed)
			(pads allowed)
			(copperpour allowed)
			(footprints allowed)
		)
		(placement
			(enabled no)
			(sheetname "")
		)
		(fill
			(thermal_gap 0.5)
			(thermal_bridge_width 0.5)
			(island_removal_mode 0)
		)
		(polygon
			(pts
				(xy 455.094594 -201.876406) (xy 457.126594 -201.876406) (xy 457.126594 -202.105006) (xy 455.094594 -202.105006)
				(xy 454.95845 -202.105006) (xy 454.91146 -202.105006) (xy 454.91146 -201.876406) (xy 454.95845 -201.876406)
			)
		)
	)
	(zone
		(layer "F.Cu")
		(hatch none 0.5)
		(connect_pads
			(clearance 0)
		)
		(min_thickness 0.25)
		(keepout
			(tracks allowed)
			(vias allowed)
			(pads allowed)
			(copperpour allowed)
			(footprints allowed)
		)
		(placement
			(enabled no)
			(sheetname "")
		)
		(fill
			(thermal_gap 0.5)
			(thermal_bridge_width 0.5)
			(island_removal_mode 0)
		)
		(polygon
			(pts
				(xy 157.791658 -295.604946) (xy 157.791658 -295.376346) (xy 159.823658 -295.376346) (xy 159.823658 -295.604946)
			)
		)
	)
	(zone
		(layer "F.Cu")
		(hatch none 0.5)
		(connect_pads
			(clearance 0)
		)
		(min_thickness 0.25)
		(keepout
			(tracks allowed)
			(vias allowed)
			(pads allowed)
			(copperpour allowed)
			(footprints allowed)
		)
		(placement
			(enabled no)
			(sheetname "")
		)
		(fill
			(thermal_gap 0.5)
			(thermal_bridge_width 0.5)
			(island_removal_mode 0)
		)
		(polygon
			(pts
				(xy 87.14994 -288.145728) (xy 87.43696 -288.145728) (xy 87.46744 -288.115248) (xy 87.46744 -287.487868)
				(xy 87.38108 -287.401508) (xy 87.19312 -287.401508) (xy 87.11946 -287.475168) (xy 87.11946 -288.115248)
			)
		)
	)
	(zone
		(layer "F.Cu")
		(hatch none 0.5)
		(connect_pads
			(clearance 0)
		)
		(min_thickness 0.25)
		(keepout
			(tracks allowed)
			(vias allowed)
			(pads allowed)
			(copperpour allowed)
			(footprints allowed)
		)
		(placement
			(enabled no)
			(sheetname "")
		)
		(fill
			(thermal_gap 0.5)
			(thermal_bridge_width 0.5)
			(island_removal_mode 0)
		)
		(polygon
			(pts
				(xy 180.423058 -310.055006) (xy 180.423058 -309.826406) (xy 182.455058 -309.826406) (xy 182.455058 -310.055006)
			)
		)
	)
	(zone
		(layer "F.Cu")
		(hatch none 0.5)
		(connect_pads
			(clearance 0)
		)
		(min_thickness 0.25)
		(keepout
			(tracks allowed)
			(vias allowed)
			(pads allowed)
			(copperpour allowed)
			(footprints allowed)
		)
		(placement
			(enabled no)
			(sheetname "")
		)
		(fill
			(thermal_gap 0.5)
			(thermal_bridge_width 0.5)
			(island_removal_mode 0)
		)
		(polygon
			(pts
				(xy 135.267446 -340.890352) (xy 135.267446 -344.895932) (xy 135.747506 -345.375992) (xy 137.812526 -345.375992)
				(xy 138.084306 -345.104212) (xy 138.084306 -343.250012) (xy 138.335766 -342.998552) (xy 140.256006 -342.998552)
				(xy 140.672566 -342.581992) (xy 140.672566 -341.091012) (xy 140.024866 -340.443312) (xy 135.714486 -340.443312)
			)
		)
	)
	(zone
		(layer "F.Cu")
		(hatch none 0.5)
		(connect_pads
			(clearance 0)
		)
		(min_thickness 0.25)
		(keepout
			(tracks allowed)
			(vias allowed)
			(pads allowed)
			(copperpour allowed)
			(footprints allowed)
		)
		(placement
			(enabled no)
			(sheetname "")
		)
		(fill
			(thermal_gap 0.5)
			(thermal_bridge_width 0.5)
			(island_removal_mode 0)
		)
		(polygon
			(pts
				(xy 176.979326 -306.426362) (xy 179.011326 -306.426362) (xy 179.011326 -306.654962) (xy 176.979326 -306.654962)
				(xy 176.843182 -306.654962) (xy 176.796192 -306.654962) (xy 176.796192 -306.426362) (xy 176.843182 -306.426362)
			)
		)
	)
	(zone
		(layer "F.Cu")
		(hatch none 0.5)
		(connect_pads
			(clearance 0)
		)
		(min_thickness 0.25)
		(keepout
			(tracks allowed)
			(vias allowed)
			(pads allowed)
			(copperpour allowed)
			(footprints not_allowed)
		)
		(placement
			(enabled no)
			(sheetname "")
		)
		(fill
			(thermal_gap 0.5)
			(thermal_bridge_width 0.5)
			(island_removal_mode 0)
		)
		(polygon
			(pts
				(xy 347.300042 -440.989974) (xy 350.499934 -440.989974) (xy 350.499934 -417.889944) (xy 310.20004 -417.889944)
				(xy 310.20004 -440.989974) (xy 313.399932 -440.989974) (xy 313.399932 -421.09009) (xy 347.300042 -421.09009)
			)
		)
	)
	(zone
		(layer "F.Cu")
		(hatch none 0.5)
		(connect_pads
			(clearance 0)
		)
		(min_thickness 0.25)
		(keepout
			(tracks allowed)
			(vias allowed)
			(pads allowed)
			(copperpour allowed)
			(footprints allowed)
		)
		(placement
			(enabled no)
			(sheetname "")
		)
		(fill
			(thermal_gap 0.5)
			(thermal_bridge_width 0.5)
			(island_removal_mode 0)
		)
		(polygon
			(pts
				(xy 305.510946 -366.12195) (xy 305.909726 -365.72317) (xy 305.909726 -364.03407) (xy 305.731926 -363.85627)
				(xy 301.594266 -363.85627) (xy 301.439326 -364.01121) (xy 301.439326 -365.88065) (xy 301.680626 -366.12195)
			)
		)
	)
	(zone
		(layer "F.Cu")
		(hatch none 0.5)
		(connect_pads
			(clearance 0)
		)
		(min_thickness 0.25)
		(keepout
			(tracks allowed)
			(vias allowed)
			(pads allowed)
			(copperpour allowed)
			(footprints not_allowed)
		)
		(placement
			(enabled no)
			(sheetname "")
		)
		(fill
			(thermal_gap 0.5)
			(thermal_bridge_width 0.5)
			(island_removal_mode 0)
		)
		(polygon
			(pts
				(xy 446.699894 -409.385008) (xy 446.699894 -420.885112) (xy 453.200008 -420.885112) (xy 453.200008 -409.385008)
			)
		)
	)
	(zone
		(layer "F.Cu")
		(hatch none 0.5)
		(connect_pads
			(clearance 0)
		)
		(min_thickness 0.25)
		(keepout
			(tracks allowed)
			(vias allowed)
			(pads allowed)
			(copperpour allowed)
			(footprints allowed)
		)
		(placement
			(enabled no)
			(sheetname "")
		)
		(fill
			(thermal_gap 0.5)
			(thermal_bridge_width 0.5)
			(island_removal_mode 0)
		)
		(polygon
			(pts
				(xy 443.450726 -314.304934) (xy 443.450726 -314.076334) (xy 445.482726 -314.076334) (xy 445.482726 -314.304934)
			)
		)
	)
	(zone
		(layer "F.Cu")
		(hatch none 0.5)
		(connect_pads
			(clearance 0)
		)
		(min_thickness 0.25)
		(keepout
			(tracks allowed)
			(vias allowed)
			(pads allowed)
			(copperpour allowed)
			(footprints allowed)
		)
		(placement
			(enabled no)
			(sheetname "")
		)
		(fill
			(thermal_gap 0.5)
			(thermal_bridge_width 0.5)
			(island_removal_mode 0)
		)
		(polygon
			(pts
				(xy 195.510658 -304.95494) (xy 195.510658 -304.72634) (xy 197.542658 -304.72634) (xy 197.542658 -304.95494)
			)
		)
	)
	(zone
		(layer "F.Cu")
		(hatch none 0.5)
		(connect_pads
			(clearance 0)
		)
		(min_thickness 0.25)
		(keepout
			(tracks allowed)
			(vias allowed)
			(pads allowed)
			(copperpour allowed)
			(footprints allowed)
		)
		(placement
			(enabled no)
			(sheetname "")
		)
		(fill
			(thermal_gap 0.5)
			(thermal_bridge_width 0.5)
			(island_removal_mode 0)
		)
		(polygon
			(pts
				(xy 413.275526 -316.004956) (xy 413.275526 -315.776356) (xy 415.307526 -315.776356) (xy 415.307526 -316.004956)
			)
		)
	)
	(zone
		(layer "F.Cu")
		(hatch none 0.5)
		(connect_pads
			(clearance 0)
		)
		(min_thickness 0.25)
		(keepout
			(tracks allowed)
			(vias allowed)
			(pads allowed)
			(copperpour allowed)
			(footprints allowed)
		)
		(placement
			(enabled no)
			(sheetname "")
		)
		(fill
			(thermal_gap 0.5)
			(thermal_bridge_width 0.5)
			(island_removal_mode 0)
		)
		(polygon
			(pts
				(xy 26.20391 -297.416474) (xy 26.20391 -296.972736) (xy 28.529026 -296.972736) (xy 28.529026 -297.416474)
			)
		)
	)
	(zone
		(layer "F.Cu")
		(hatch none 0.5)
		(connect_pads
			(clearance 0)
		)
		(min_thickness 0.25)
		(keepout
			(tracks allowed)
			(vias allowed)
			(pads allowed)
			(copperpour allowed)
			(footprints allowed)
		)
		(placement
			(enabled no)
			(sheetname "")
		)
		(fill
			(thermal_gap 0.5)
			(thermal_bridge_width 0.5)
			(island_removal_mode 0)
		)
		(polygon
			(pts
				(xy 409.831794 -261.605014) (xy 409.831794 -261.376414) (xy 411.863794 -261.376414) (xy 411.863794 -261.605014)
			)
		)
	)
	(zone
		(layer "F.Cu")
		(hatch none 0.5)
		(connect_pads
			(clearance 0)
		)
		(min_thickness 0.25)
		(keepout
			(tracks allowed)
			(vias allowed)
			(pads allowed)
			(copperpour allowed)
			(footprints allowed)
		)
		(placement
			(enabled no)
			(sheetname "")
		)
		(fill
			(thermal_gap 0.5)
			(thermal_bridge_width 0.5)
			(island_removal_mode 0)
		)
		(polygon
			(pts
				(xy 262.50011 -308.46649) (xy 262.50011 -308.022752) (xy 264.825226 -308.022752) (xy 264.825226 -308.46649)
			)
		)
	)
	(zone
		(layer "F.Cu")
		(hatch none 0.5)
		(connect_pads
			(clearance 0)
		)
		(min_thickness 0.25)
		(keepout
			(tracks allowed)
			(vias allowed)
			(pads allowed)
			(copperpour allowed)
			(footprints not_allowed)
		)
		(placement
			(enabled no)
			(sheetname "")
		)
		(fill
			(thermal_gap 0.5)
			(thermal_bridge_width 0.5)
			(island_removal_mode 0)
		)
		(polygon
			(pts
				(xy 384.122168 -339.214968) (xy 384.122168 -314.770008) (xy 330.499212 -314.770008) (xy 330.499212 -339.214968)
				(xy 332.4987 -339.214968)
				(arc
					(start 332.4987 -334.724248)
					(mid 332.879453 -333.805029)
					(end 333.798672 -333.424276)
				)
				(xy 340.659212 -333.424276)
				(arc
					(start 340.659212 -331.314044)
					(mid 341.039965 -330.394825)
					(end 341.959184 -330.014072)
				)
				(arc
					(start 372.661688 -330.014072)
					(mid 373.580907 -330.394825)
					(end 373.96166 -331.314044)
				)
				(xy 373.96166 -333.424276)
				(arc
					(start 380.8222 -333.424276)
					(mid 381.741419 -333.805029)
					(end 382.122172 -334.724248)
				)
				(xy 382.122172 -339.214968)
			)
		)
	)
	(zone
		(layer "F.Cu")
		(hatch none 0.5)
		(connect_pads
			(clearance 0)
		)
		(min_thickness 0.25)
		(keepout
			(tracks allowed)
			(vias allowed)
			(pads allowed)
			(copperpour allowed)
			(footprints allowed)
		)
		(placement
			(enabled no)
			(sheetname "")
		)
		(fill
			(thermal_gap 0.5)
			(thermal_bridge_width 0.5)
			(island_removal_mode 0)
		)
		(polygon
			(pts
				(xy 428.363126 -211.455) (xy 428.363126 -211.2264) (xy 430.395126 -211.2264) (xy 430.395126 -211.455)
			)
		)
	)
	(zone
		(layer "F.Cu")
		(hatch none 0.5)
		(connect_pads
			(clearance 0)
		)
		(min_thickness 0.25)
		(keepout
			(tracks allowed)
			(vias allowed)
			(pads allowed)
			(copperpour allowed)
			(footprints allowed)
		)
		(placement
			(enabled no)
			(sheetname "")
		)
		(fill
			(thermal_gap 0.5)
			(thermal_bridge_width 0.5)
			(island_removal_mode 0)
		)
		(polygon
			(pts
				(xy 455.094594 -297.076368) (xy 457.126594 -297.076368) (xy 457.126594 -297.304968) (xy 455.094594 -297.304968)
				(xy 454.95845 -297.304968) (xy 454.91146 -297.304968) (xy 454.91146 -297.076368) (xy 454.95845 -297.076368)
			)
		)
	)
	(zone
		(layer "F.Cu")
		(hatch none 0.5)
		(connect_pads
			(clearance 0)
		)
		(min_thickness 0.25)
		(keepout
			(tracks allowed)
			(vias allowed)
			(pads allowed)
			(copperpour allowed)
			(footprints allowed)
		)
		(placement
			(enabled no)
			(sheetname "")
		)
		(fill
			(thermal_gap 0.5)
			(thermal_bridge_width 0.5)
			(island_removal_mode 0)
		)
		(polygon
			(pts
				(xy 14.560042 -271.916652) (xy 14.560042 -271.472914) (xy 16.885158 -271.472914) (xy 16.885158 -271.916652)
			)
		)
	)
	(zone
		(layer "F.Cu")
		(hatch none 0.5)
		(connect_pads
			(clearance 0)
		)
		(min_thickness 0.25)
		(keepout
			(tracks not_allowed)
			(vias allowed)
			(pads allowed)
			(copperpour not_allowed)
			(footprints allowed)
		)
		(placement
			(enabled no)
			(sheetname "")
		)
		(fill
			(thermal_gap 0.5)
			(thermal_bridge_width 0.5)
			(island_removal_mode 0)
		)
		(polygon
			(pts
				(arc
					(start 165.1 -160.50006)
					(mid 167.900096 -157.699964)
					(end 170.699938 -160.50006)
				)
				(arc
					(start 170.699938 -160.50006)
					(mid 167.900096 -163.299902)
					(end 165.1 -160.50006)
				)
			)
		)
	)
	(zone
		(layer "F.Cu")
		(hatch none 0.5)
		(connect_pads
			(clearance 0)
		)
		(min_thickness 0.25)
		(keepout
			(tracks allowed)
			(vias allowed)
			(pads allowed)
			(copperpour allowed)
			(footprints allowed)
		)
		(placement
			(enabled no)
			(sheetname "")
		)
		(fill
			(thermal_gap 0.5)
			(thermal_bridge_width 0.5)
			(island_removal_mode 0)
		)
		(polygon
			(pts
				(xy 428.363126 -231.85501) (xy 428.363126 -231.62641) (xy 430.395126 -231.62641) (xy 430.395126 -231.85501)
			)
		)
	)
	(zone
		(layer "F.Cu")
		(hatch none 0.5)
		(connect_pads
			(clearance 0)
		)
		(min_thickness 0.25)
		(keepout
			(tracks allowed)
			(vias allowed)
			(pads allowed)
			(copperpour allowed)
			(footprints allowed)
		)
		(placement
			(enabled no)
			(sheetname "")
		)
		(fill
			(thermal_gap 0.5)
			(thermal_bridge_width 0.5)
			(island_removal_mode 0)
		)
		(polygon
			(pts
				(xy 262.50011 -252.366526) (xy 262.50011 -251.922788) (xy 264.825226 -251.922788) (xy 264.825226 -252.366526)
			)
		)
	)
	(zone
		(layer "F.Cu")
		(hatch none 0.5)
		(connect_pads
			(clearance 0)
		)
		(min_thickness 0.25)
		(keepout
			(tracks allowed)
			(vias allowed)
			(pads allowed)
			(copperpour allowed)
			(footprints allowed)
		)
		(placement
			(enabled no)
			(sheetname "")
		)
		(fill
			(thermal_gap 0.5)
			(thermal_bridge_width 0.5)
			(island_removal_mode 0)
		)
		(polygon
			(pts
				(xy 311.91708 -281.266646) (xy 311.91708 -280.822908) (xy 314.15228 -280.822908) (xy 314.15228 -281.266646)
			)
		)
	)
	(zone
		(layer "F.Cu")
		(hatch none 0.5)
		(connect_pads
			(clearance 0)
		)
		(min_thickness 0.25)
		(keepout
			(tracks allowed)
			(vias allowed)
			(pads allowed)
			(copperpour allowed)
			(footprints allowed)
		)
		(placement
			(enabled no)
			(sheetname "")
		)
		(fill
			(thermal_gap 0.5)
			(thermal_bridge_width 0.5)
			(island_removal_mode 0)
		)
		(polygon
			(pts
				(xy 192.066926 -210.376262) (xy 194.098926 -210.376262) (xy 194.098926 -210.604862) (xy 192.066926 -210.604862)
				(xy 191.935608 -210.604862) (xy 191.9097 -210.604862) (xy 191.9097 -210.376262) (xy 191.935608 -210.376262)
			)
		)
	)
	(zone
		(layer "F.Cu")
		(hatch none 0.5)
		(connect_pads
			(clearance 0)
		)
		(min_thickness 0.25)
		(keepout
			(tracks allowed)
			(vias allowed)
			(pads allowed)
			(copperpour allowed)
			(footprints allowed)
		)
		(placement
			(enabled no)
			(sheetname "")
		)
		(fill
			(thermal_gap 0.5)
			(thermal_bridge_width 0.5)
			(island_removal_mode 0)
		)
		(polygon
			(pts
				(xy 180.423058 -314.304934) (xy 180.423058 -314.076334) (xy 182.455058 -314.076334) (xy 182.455058 -314.304934)
			)
		)
	)
	(zone
		(layer "F.Cu")
		(hatch none 0.5)
		(connect_pads
			(clearance 0)
		)
		(min_thickness 0.25)
		(keepout
			(tracks allowed)
			(vias allowed)
			(pads allowed)
			(copperpour allowed)
			(footprints allowed)
		)
		(placement
			(enabled no)
			(sheetname "")
		)
		(fill
			(thermal_gap 0.5)
			(thermal_bridge_width 0.5)
			(island_removal_mode 0)
		)
		(polygon
			(pts
				(xy 54.480714 -18.570702) (xy 54.480714 -15.436088) (xy 56.259476 -15.436088) (xy 56.259476 -18.570702)
			)
		)
	)
	(zone
		(layer "F.Cu")
		(hatch none 0.5)
		(connect_pads
			(clearance 0)
		)
		(min_thickness 0.25)
		(keepout
			(tracks allowed)
			(vias allowed)
			(pads allowed)
			(copperpour allowed)
			(footprints allowed)
		)
		(placement
			(enabled no)
			(sheetname "")
		)
		(fill
			(thermal_gap 0.5)
			(thermal_bridge_width 0.5)
			(island_removal_mode 0)
		)
		(polygon
			(pts
				(xy 207.154526 -287.726374) (xy 209.186526 -287.726374) (xy 209.186526 -287.954974) (xy 207.154526 -287.954974)
				(xy 207.018382 -287.954974) (xy 206.971392 -287.954974) (xy 206.971392 -287.726374) (xy 207.018382 -287.726374)
			)
		)
	)
	(zone
		(layer "F.Cu")
		(hatch none 0.5)
		(connect_pads
			(clearance 0)
		)
		(min_thickness 0.25)
		(keepout
			(tracks not_allowed)
			(vias allowed)
			(pads allowed)
			(copperpour not_allowed)
			(footprints allowed)
		)
		(placement
			(enabled no)
			(sheetname "")
		)
		(fill
			(thermal_gap 0.5)
			(thermal_bridge_width 0.5)
			(island_removal_mode 0)
		)
		(polygon
			(pts
				(xy 334.73263 -339.670644) (xy 338.71662 -339.670644) (xy 338.71662 -339.594952) (xy 338.6074 -339.485732)
				(xy 337.120484 -339.485732) (xy 337.120484 -337.326732) (xy 339.277198 -337.326732) (xy 339.277198 -337.07705)
				(xy 336.89036 -337.07705) (xy 336.89036 -337.393788) (xy 336.829146 -337.393788) (xy 336.829146 -339.430106)
				(xy 334.974946 -339.430106) (xy 334.974946 -339.18906) (xy 334.73263 -339.18906)
			)
		)
	)
	(zone
		(layer "F.Cu")
		(hatch none 0.5)
		(connect_pads
			(clearance 0)
		)
		(min_thickness 0.25)
		(keepout
			(tracks allowed)
			(vias allowed)
			(pads allowed)
			(copperpour allowed)
			(footprints allowed)
		)
		(placement
			(enabled no)
			(sheetname "")
		)
		(fill
			(thermal_gap 0.5)
			(thermal_bridge_width 0.5)
			(island_removal_mode 0)
		)
		(polygon
			(pts
				(xy 307.76291 -302.51654) (xy 307.76291 -302.072802) (xy 310.088026 -302.072802) (xy 310.088026 -302.51654)
			)
		)
	)
	(zone
		(layer "F.Cu")
		(hatch none 0.5)
		(connect_pads
			(clearance 0)
		)
		(min_thickness 0.25)
		(keepout
			(tracks allowed)
			(vias allowed)
			(pads allowed)
			(copperpour allowed)
			(footprints allowed)
		)
		(placement
			(enabled no)
			(sheetname "")
		)
		(fill
			(thermal_gap 0.5)
			(thermal_bridge_width 0.5)
			(island_removal_mode 0)
		)
		(polygon
			(pts
				(xy 197.553834 -270.95704) (xy 195.521834 -270.95704) (xy 195.521834 -270.954754) (xy 195.343018 -270.954754)
				(xy 195.343018 -270.717518) (xy 195.205096 -270.717518) (xy 195.161916 -270.674338) (xy 195.161916 -270.541496)
				(xy 195.161916 -270.237458) (xy 195.23456 -270.164814) (xy 197.774814 -270.164814) (xy 197.916038 -270.306038)
				(xy 197.916038 -270.503142) (xy 197.834504 -270.584676) (xy 197.834504 -270.95704) (xy 197.736968 -270.95704)
				(xy 197.689978 -270.95704)
			)
		)
	)
	(zone
		(layer "F.Cu")
		(hatch none 0.5)
		(connect_pads
			(clearance 0)
		)
		(min_thickness 0.25)
		(keepout
			(tracks allowed)
			(vias allowed)
			(pads allowed)
			(copperpour allowed)
			(footprints allowed)
		)
		(placement
			(enabled no)
			(sheetname "")
		)
		(fill
			(thermal_gap 0.5)
			(thermal_bridge_width 0.5)
			(island_removal_mode 0)
		)
		(polygon
			(pts
				(xy 304.319178 -226.016566) (xy 304.319178 -225.572828) (xy 306.644294 -225.572828) (xy 306.644294 -226.016566)
			)
		)
	)
	(zone
		(layer "F.Cu")
		(hatch none 0.5)
		(connect_pads
			(clearance 0)
		)
		(min_thickness 0.25)
		(keepout
			(tracks allowed)
			(vias allowed)
			(pads allowed)
			(copperpour allowed)
			(footprints allowed)
		)
		(placement
			(enabled no)
			(sheetname "")
		)
		(fill
			(thermal_gap 0.5)
			(thermal_bridge_width 0.5)
			(island_removal_mode 0)
		)
		(polygon
			(pts
				(xy 180.423058 -241.205004) (xy 180.423058 -240.976404) (xy 182.455058 -240.976404) (xy 182.455058 -241.205004)
			)
		)
	)
	(zone
		(layer "F.Cu")
		(hatch none 0.5)
		(connect_pads
			(clearance 0)
		)
		(min_thickness 0.25)
		(keepout
			(tracks allowed)
			(vias allowed)
			(pads allowed)
			(copperpour allowed)
			(footprints allowed)
		)
		(placement
			(enabled no)
			(sheetname "")
		)
		(fill
			(thermal_gap 0.5)
			(thermal_bridge_width 0.5)
			(island_removal_mode 0)
		)
		(polygon
			(pts
				(xy 428.363126 -274.354798) (xy 428.363126 -274.126198) (xy 430.395126 -274.126198) (xy 430.395126 -274.354798)
			)
		)
	)
	(zone
		(layer "F.Cu")
		(hatch none 0.5)
		(connect_pads
			(clearance 0)
		)
		(min_thickness 0.25)
		(keepout
			(tracks allowed)
			(vias allowed)
			(pads allowed)
			(copperpour allowed)
			(footprints allowed)
		)
		(placement
			(enabled no)
			(sheetname "")
		)
		(fill
			(thermal_gap 0.5)
			(thermal_bridge_width 0.5)
			(island_removal_mode 0)
		)
		(polygon
			(pts
				(xy 392.80084 -9.700768) (xy 392.80084 -5.888228) (xy 407.8097 -5.888228) (xy 407.8097 -9.700768)
			)
		)
	)
	(zone
		(layer "F.Cu")
		(hatch none 0.5)
		(connect_pads
			(clearance 0)
		)
		(min_thickness 0.25)
		(keepout
			(tracks allowed)
			(vias allowed)
			(pads allowed)
			(copperpour allowed)
			(footprints allowed)
		)
		(placement
			(enabled no)
			(sheetname "")
		)
		(fill
			(thermal_gap 0.5)
			(thermal_bridge_width 0.5)
			(island_removal_mode 0)
		)
		(polygon
			(pts
				(xy 85.70976 -285.750508) (xy 85.99678 -285.750508) (xy 86.02726 -285.720028) (xy 86.02726 -285.092648)
				(xy 85.9409 -285.006288) (xy 85.75294 -285.006288) (xy 85.67928 -285.079948) (xy 85.67928 -285.720028)
			)
		)
	)
	(zone
		(layer "F.Cu")
		(hatch none 0.5)
		(connect_pads
			(clearance 0)
		)
		(min_thickness 0.25)
		(keepout
			(tracks allowed)
			(vias allowed)
			(pads allowed)
			(copperpour allowed)
			(footprints allowed)
		)
		(placement
			(enabled no)
			(sheetname "")
		)
		(fill
			(thermal_gap 0.5)
			(thermal_bridge_width 0.5)
			(island_removal_mode 0)
		)
		(polygon
			(pts
				(xy 277.58771 -206.46644) (xy 277.58771 -206.022702) (xy 279.912826 -206.022702) (xy 279.912826 -206.46644)
			)
		)
	)
	(zone
		(layer "F.Cu")
		(hatch none 0.5)
		(connect_pads
			(clearance 0)
		)
		(min_thickness 0.25)
		(keepout
			(tracks allowed)
			(vias allowed)
			(pads allowed)
			(copperpour allowed)
			(footprints allowed)
		)
		(placement
			(enabled no)
			(sheetname "")
		)
		(fill
			(thermal_gap 0.5)
			(thermal_bridge_width 0.5)
			(island_removal_mode 0)
		)
		(polygon
			(pts
				(xy 176.979326 -298.77639) (xy 179.011326 -298.77639) (xy 179.011326 -299.00499) (xy 176.979326 -299.00499)
				(xy 176.843182 -299.00499) (xy 176.796192 -299.00499) (xy 176.796192 -298.77639) (xy 176.843182 -298.77639)
			)
		)
	)
	(zone
		(layer "F.Cu")
		(hatch none 0.5)
		(connect_pads
			(clearance 0)
		)
		(min_thickness 0.25)
		(keepout
			(tracks not_allowed)
			(vias allowed)
			(pads allowed)
			(copperpour not_allowed)
			(footprints allowed)
		)
		(placement
			(enabled no)
			(sheetname "")
		)
		(fill
			(thermal_gap 0.5)
			(thermal_bridge_width 0.5)
			(island_removal_mode 0)
		)
		(polygon
			(pts
				(xy 103.11384 -336.26044) (xy 107.03814 -336.26044) (xy 107.03814 -336.215228) (xy 106.89844 -336.075528)
				(xy 105.501694 -336.075528) (xy 105.501694 -333.916528) (xy 107.658408 -333.916528) (xy 107.658408 -333.666846)
				(xy 105.34904 -333.666846) (xy 105.34904 -334.002888) (xy 105.210356 -334.002888) (xy 105.210356 -336.019902)
				(xy 103.356156 -336.019902) (xy 103.356156 -335.778856) (xy 103.11384 -335.778856)
			)
		)
	)
	(zone
		(layer "F.Cu")
		(hatch none 0.5)
		(connect_pads
			(clearance 0)
		)
		(min_thickness 0.25)
		(keepout
			(tracks allowed)
			(vias allowed)
			(pads allowed)
			(copperpour allowed)
			(footprints allowed)
		)
		(placement
			(enabled no)
			(sheetname "")
		)
		(fill
			(thermal_gap 0.5)
			(thermal_bridge_width 0.5)
			(island_removal_mode 0)
		)
		(polygon
			(pts
				(xy 56.379364 -201.366374) (xy 56.379364 -200.922636) (xy 58.70448 -200.922636) (xy 58.70448 -201.366374)
			)
		)
	)
	(zone
		(layer "F.Cu")
		(hatch none 0.5)
		(connect_pads
			(clearance 0)
		)
		(min_thickness 0.25)
		(keepout
			(tracks allowed)
			(vias allowed)
			(pads allowed)
			(copperpour allowed)
			(footprints allowed)
		)
		(placement
			(enabled no)
			(sheetname "")
		)
		(fill
			(thermal_gap 0.5)
			(thermal_bridge_width 0.5)
			(island_removal_mode 0)
		)
		(polygon
			(pts
				(xy 311.86628 -220.066616) (xy 311.86628 -219.622878) (xy 314.188094 -219.622878) (xy 314.188094 -220.066616)
			)
		)
	)
	(zone
		(layer "F.Cu")
		(hatch none 0.5)
		(connect_pads
			(clearance 0)
		)
		(min_thickness 0.25)
		(keepout
			(tracks allowed)
			(vias allowed)
			(pads allowed)
			(copperpour allowed)
			(footprints allowed)
		)
		(placement
			(enabled no)
			(sheetname "")
		)
		(fill
			(thermal_gap 0.5)
			(thermal_bridge_width 0.5)
			(island_removal_mode 0)
		)
		(polygon
			(pts
				(xy 59.822842 -252.366526) (xy 59.822842 -251.922788) (xy 62.147958 -251.922788) (xy 62.147958 -252.366526)
			)
		)
	)
	(zone
		(layer "F.Cu")
		(hatch none 0.5)
		(connect_pads
			(clearance 0)
		)
		(min_thickness 0.25)
		(keepout
			(tracks allowed)
			(vias allowed)
			(pads allowed)
			(copperpour allowed)
			(footprints allowed)
		)
		(placement
			(enabled no)
			(sheetname "")
		)
		(fill
			(thermal_gap 0.5)
			(thermal_bridge_width 0.5)
			(island_removal_mode 0)
		)
		(polygon
			(pts
				(xy 332.56728 -255.948688) (xy 332.9305 -255.948688) (xy 333.00162 -255.877568) (xy 333.00162 -255.788668)
				(xy 332.61554 -255.402588) (xy 332.36916 -255.402588) (xy 332.2828 -255.488948) (xy 332.2828 -255.664208)
			)
		)
	)
	(zone
		(layer "F.Cu")
		(hatch none 0.5)
		(connect_pads
			(clearance 0)
		)
		(min_thickness 0.25)
		(keepout
			(tracks allowed)
			(vias allowed)
			(pads allowed)
			(copperpour allowed)
			(footprints allowed)
		)
		(placement
			(enabled no)
			(sheetname "")
		)
		(fill
			(thermal_gap 0.5)
			(thermal_bridge_width 0.5)
			(island_removal_mode 0)
		)
		(polygon
			(pts
				(xy 428.363126 -197.854824) (xy 428.363126 -197.626224) (xy 430.395126 -197.626224) (xy 430.395126 -197.854824)
			)
		)
	)
	(zone
		(layer "F.Cu")
		(hatch none 0.5)
		(connect_pads
			(clearance 0)
		)
		(min_thickness 0.25)
		(keepout
			(tracks allowed)
			(vias allowed)
			(pads allowed)
			(copperpour allowed)
			(footprints allowed)
		)
		(placement
			(enabled no)
			(sheetname "")
		)
		(fill
			(thermal_gap 0.5)
			(thermal_bridge_width 0.5)
			(island_removal_mode 0)
		)
		(polygon
			(pts
				(xy 274.143978 -205.616556) (xy 274.143978 -205.172818) (xy 276.469094 -205.172818) (xy 276.469094 -205.616556)
			)
		)
	)
	(zone
		(layer "F.Cu")
		(hatch none 0.5)
		(connect_pads
			(clearance 0)
		)
		(min_thickness 0.25)
		(keepout
			(tracks allowed)
			(vias allowed)
			(pads allowed)
			(copperpour allowed)
			(footprints allowed)
		)
		(placement
			(enabled no)
			(sheetname "")
		)
		(fill
			(thermal_gap 0.5)
			(thermal_bridge_width 0.5)
			(island_removal_mode 0)
		)
		(polygon
			(pts
				(xy 312.712862 -404.802594) (xy 312.712862 -399.959576) (xy 314.597288 -399.959576) (xy 314.597288 -404.802594)
			)
		)
	)
	(zone
		(layer "F.Cu")
		(hatch none 0.5)
		(connect_pads
			(clearance 0)
		)
		(min_thickness 0.25)
		(keepout
			(tracks allowed)
			(vias allowed)
			(pads allowed)
			(copperpour allowed)
			(footprints allowed)
		)
		(placement
			(enabled no)
			(sheetname "")
		)
		(fill
			(thermal_gap 0.5)
			(thermal_bridge_width 0.5)
			(island_removal_mode 0)
		)
		(polygon
			(pts
				(xy 311.89168 -272.322798) (xy 314.17768 -272.322798) (xy 314.453778 -272.322798) (xy 314.453778 -273.28876)
				(xy 311.522364 -273.28876) (xy 311.522364 -272.322798)
			)
		)
	)
	(zone
		(layer "F.Cu")
		(hatch none 0.5)
		(connect_pads
			(clearance 0)
		)
		(min_thickness 0.25)
		(keepout
			(tracks allowed)
			(vias allowed)
			(pads allowed)
			(copperpour allowed)
			(footprints allowed)
		)
		(placement
			(enabled no)
			(sheetname "")
		)
		(fill
			(thermal_gap 0.5)
			(thermal_bridge_width 0.5)
			(island_removal_mode 0)
		)
		(polygon
			(pts
				(xy 165.335458 -304.95494) (xy 165.335458 -304.72634) (xy 167.367458 -304.72634) (xy 167.367458 -304.95494)
			)
		)
	)
	(zone
		(layer "F.Cu")
		(hatch none 0.5)
		(connect_pads
			(clearance 0)
		)
		(min_thickness 0.25)
		(keepout
			(tracks allowed)
			(vias allowed)
			(pads allowed)
			(copperpour allowed)
			(footprints allowed)
		)
		(placement
			(enabled no)
			(sheetname "")
		)
		(fill
			(thermal_gap 0.5)
			(thermal_bridge_width 0.5)
			(island_removal_mode 0)
		)
		(polygon
			(pts
				(xy 428.363126 -289.654996) (xy 428.363126 -289.426396) (xy 430.395126 -289.426396) (xy 430.395126 -289.654996)
			)
		)
	)
	(zone
		(layer "F.Cu")
		(hatch none 0.5)
		(connect_pads
			(clearance 0)
		)
		(min_thickness 0.25)
		(keepout
			(tracks allowed)
			(vias allowed)
			(pads allowed)
			(copperpour allowed)
			(footprints not_allowed)
		)
		(placement
			(enabled no)
			(sheetname "")
		)
		(fill
			(thermal_gap 0.5)
			(thermal_bridge_width 0.5)
			(island_removal_mode 0)
		)
		(polygon
			(pts
				(arc
					(start 287.638236 -440.989974)
					(mid 293.550172 -427.59962)
					(end 299.461682 -440.989974)
				)
			)
		)
	)
	(zone
		(layer "F.Cu")
		(hatch none 0.5)
		(connect_pads
			(clearance 0)
		)
		(min_thickness 0.25)
		(keepout
			(tracks allowed)
			(vias allowed)
			(pads allowed)
			(copperpour allowed)
			(footprints allowed)
		)
		(placement
			(enabled no)
			(sheetname "")
		)
		(fill
			(thermal_gap 0.5)
			(thermal_bridge_width 0.5)
			(island_removal_mode 0)
		)
		(polygon
			(pts
				(xy 334.155542 -404.802594) (xy 334.155542 -399.959576) (xy 336.039968 -399.959576) (xy 336.039968 -404.802594)
			)
		)
	)
	(zone
		(layer "F.Cu")
		(hatch none 0.5)
		(connect_pads
			(clearance 0)
		)
		(min_thickness 0.25)
		(keepout
			(tracks allowed)
			(vias allowed)
			(pads allowed)
			(copperpour allowed)
			(footprints allowed)
		)
		(placement
			(enabled no)
			(sheetname "")
		)
		(fill
			(thermal_gap 0.5)
			(thermal_bridge_width 0.5)
			(island_removal_mode 0)
		)
		(polygon
			(pts
				(xy 136.97204 -286.560768) (xy 137.25906 -286.560768) (xy 137.28954 -286.530288) (xy 137.28954 -285.902908)
				(xy 137.20318 -285.816548) (xy 137.01522 -285.816548) (xy 136.94156 -285.890208) (xy 136.94156 -286.530288)
			)
		)
	)
	(zone
		(layer "F.Cu")
		(hatch none 0.5)
		(connect_pads
			(clearance 0)
		)
		(min_thickness 0.25)
		(keepout
			(tracks allowed)
			(vias allowed)
			(pads allowed)
			(copperpour allowed)
			(footprints allowed)
		)
		(placement
			(enabled no)
			(sheetname "")
		)
		(fill
			(thermal_gap 0.5)
			(thermal_bridge_width 0.5)
			(island_removal_mode 0)
		)
		(polygon
			(pts
				(xy 428.363126 -230.154988) (xy 428.363126 -229.926388) (xy 430.395126 -229.926388) (xy 430.395126 -230.154988)
			)
		)
	)
	(zone
		(layer "F.Cu")
		(hatch none 0.5)
		(connect_pads
			(clearance 0)
		)
		(min_thickness 0.25)
		(keepout
			(tracks allowed)
			(vias allowed)
			(pads allowed)
			(copperpour allowed)
			(footprints not_allowed)
		)
		(placement
			(enabled no)
			(sheetname "")
		)
		(fill
			(thermal_gap 0.5)
			(thermal_bridge_width 0.5)
			(island_removal_mode 0)
		)
		(polygon
			(pts
				(xy 222.899986 -161.699956)
				(arc
					(start 221.670118 -161.699956)
					(mid 218.841697 -162.871527)
					(end 217.670126 -165.699948)
				)
				(xy 217.670126 -185.091832) (xy 217.71991 -185.091832) (xy 217.71991 -289.776662) (xy 222.670116 -289.776662)
				(xy 222.670116 -277.199852) (xy 226.169982 -277.199852) (xy 226.169982 -249.499882) (xy 222.670116 -249.499882)
				(xy 222.670116 -220.000068) (xy 226.169982 -220.000068) (xy 226.169982 -191.499998) (xy 222.670116 -191.499998)
				(xy 222.670116 -177.200052)
				(arc
					(start 222.899986 -177.200052)
					(mid 226.435513 -175.735589)
					(end 227.899976 -172.200062)
				)
				(xy 227.899976 -107.199938) (xy 243.899944 -107.199938) (xy 243.899944 -161.699956)
				(arc
					(start 243.899944 -172.200062)
					(mid 245.364407 -175.735589)
					(end 248.899934 -177.200052)
				)
				(xy 249.130058 -177.200052) (xy 249.130058 -191.499998) (xy 245.629938 -191.499998) (xy 245.629938 -220.000068)
				(xy 249.130058 -220.000068) (xy 249.130058 -249.499882) (xy 245.629938 -249.499882) (xy 245.629938 -277.204932)
				(xy 249.130058 -277.204932) (xy 249.130058 -327.589896) (xy 222.670116 -327.589896) (xy 222.670116 -289.876738)
				(xy 217.71991 -289.876738) (xy 217.71991 -331.091794) (xy 217.670126 -331.091794) (xy 217.670126 -344.084656)
				(xy 254.130048 -344.084656) (xy 254.130048 -331.091794) (xy 254.08001 -331.091794) (xy 254.08001 -185.091832)
				(xy 254.130048 -185.091832)
				(arc
					(start 254.130048 -165.699948)
					(mid 252.958477 -162.871527)
					(end 250.130056 -161.699956)
				)
				(xy 248.899934 -161.699956)
				(arc
					(start 248.899934 -93.199966)
					(mid 248.460632 -92.139398)
					(end 247.400064 -91.700096)
				)
				(arc
					(start 224.40011 -91.700096)
					(mid 223.339452 -92.139382)
					(end 222.899986 -93.199966)
				)
			)
		)
	)
	(zone
		(layer "F.Cu")
		(hatch none 0.5)
		(connect_pads
			(clearance 0)
		)
		(min_thickness 0.25)
		(keepout
			(tracks allowed)
			(vias allowed)
			(pads allowed)
			(copperpour allowed)
			(footprints not_allowed)
		)
		(placement
			(enabled no)
			(sheetname "")
		)
		(fill
			(thermal_gap 0.5)
			(thermal_bridge_width 0.5)
			(island_removal_mode 0)
		)
		(polygon
			(pts
				(arc
					(start 228.650038 -272.50009)
					(mid 236.650022 -264.500106)
					(end 244.650006 -272.50009)
				)
				(arc
					(start 244.650006 -272.50009)
					(mid 236.650022 -280.500074)
					(end 228.650038 -272.50009)
				)
			)
		)
	)
	(zone
		(layer "F.Cu")
		(hatch none 0.5)
		(connect_pads
			(clearance 0)
		)
		(min_thickness 0.25)
		(keepout
			(tracks allowed)
			(vias allowed)
			(pads allowed)
			(copperpour allowed)
			(footprints allowed)
		)
		(placement
			(enabled no)
			(sheetname "")
		)
		(fill
			(thermal_gap 0.5)
			(thermal_bridge_width 0.5)
			(island_removal_mode 0)
		)
		(polygon
			(pts
				(xy 210.598258 -198.704962) (xy 210.598258 -198.476362) (xy 212.630258 -198.476362) (xy 212.630258 -198.704962)
			)
		)
	)
	(zone
		(layer "F.Cu")
		(hatch none 0.5)
		(connect_pads
			(clearance 0)
		)
		(min_thickness 0.25)
		(keepout
			(tracks allowed)
			(vias allowed)
			(pads allowed)
			(copperpour allowed)
			(footprints allowed)
		)
		(placement
			(enabled no)
			(sheetname "")
		)
		(fill
			(thermal_gap 0.5)
			(thermal_bridge_width 0.5)
			(island_removal_mode 0)
		)
		(polygon
			(pts
				(xy 292.67531 -202.216512) (xy 292.67531 -201.772774) (xy 295.000426 -201.772774) (xy 295.000426 -202.216512)
			)
		)
	)
	(zone
		(layer "F.Cu")
		(hatch none 0.5)
		(connect_pads
			(clearance 0)
		)
		(min_thickness 0.25)
		(keepout
			(tracks allowed)
			(vias allowed)
			(pads allowed)
			(copperpour allowed)
			(footprints allowed)
		)
		(placement
			(enabled no)
			(sheetname "")
		)
		(fill
			(thermal_gap 0.5)
			(thermal_bridge_width 0.5)
			(island_removal_mode 0)
		)
		(polygon
			(pts
				(xy 56.37911 -203.916534) (xy 56.37911 -203.472796) (xy 58.704226 -203.472796) (xy 58.704226 -203.916534)
			)
		)
	)
	(zone
		(layer "F.Cu")
		(hatch none 0.5)
		(connect_pads
			(clearance 0)
		)
		(min_thickness 0.25)
		(keepout
			(tracks allowed)
			(vias allowed)
			(pads allowed)
			(copperpour allowed)
			(footprints not_allowed)
		)
		(placement
			(enabled no)
			(sheetname "")
		)
		(fill
			(thermal_gap 0.5)
			(thermal_bridge_width 0.5)
			(island_removal_mode 0)
		)
		(polygon
			(pts
				(arc
					(start 265.895328 -51.999896)
					(mid 268.645386 -49.249838)
					(end 271.395444 -51.999896)
				)
				(arc
					(start 271.395444 -51.999896)
					(mid 268.645386 -54.749954)
					(end 265.895328 -51.999896)
				)
			)
		)
	)
	(zone
		(layer "F.Cu")
		(hatch none 0.5)
		(connect_pads
			(clearance 0)
		)
		(min_thickness 0.25)
		(keepout
			(tracks allowed)
			(vias allowed)
			(pads allowed)
			(copperpour allowed)
			(footprints allowed)
		)
		(placement
			(enabled no)
			(sheetname "")
		)
		(fill
			(thermal_gap 0.5)
			(thermal_bridge_width 0.5)
			(island_removal_mode 0)
		)
		(polygon
			(pts
				(xy 26.20391 -303.366424) (xy 26.20391 -302.922686) (xy 28.529026 -302.922686) (xy 28.529026 -303.366424)
			)
		)
	)
	(zone
		(layer "F.Cu")
		(hatch none 0.5)
		(connect_pads
			(clearance 0)
		)
		(min_thickness 0.25)
		(keepout
			(tracks not_allowed)
			(vias allowed)
			(pads allowed)
			(copperpour not_allowed)
			(footprints allowed)
		)
		(placement
			(enabled no)
			(sheetname "")
		)
		(fill
			(thermal_gap 0.5)
			(thermal_bridge_width 0.5)
			(island_removal_mode 0)
		)
		(polygon
			(pts
				(arc
					(start 1.999996 -22.29993)
					(mid 6.999986 -17.29994)
					(end 11.999976 -22.29993)
				)
				(arc
					(start 11.999976 -22.29993)
					(mid 6.999986 -27.29992)
					(end 1.999996 -22.29993)
				)
			)
		)
	)
	(zone
		(layer "F.Cu")
		(hatch none 0.5)
		(connect_pads
			(clearance 0)
		)
		(min_thickness 0.25)
		(keepout
			(tracks allowed)
			(vias allowed)
			(pads allowed)
			(copperpour allowed)
			(footprints allowed)
		)
		(placement
			(enabled no)
			(sheetname "")
		)
		(fill
			(thermal_gap 0.5)
			(thermal_bridge_width 0.5)
			(island_removal_mode 0)
		)
		(polygon
			(pts
				(xy 56.37911 -260.866636) (xy 56.37911 -260.422898) (xy 58.704226 -260.422898) (xy 58.704226 -260.866636)
			)
		)
	)
	(zone
		(layer "F.Cu")
		(hatch none 0.5)
		(connect_pads
			(clearance 0)
		)
		(min_thickness 0.25)
		(keepout
			(tracks allowed)
			(vias allowed)
			(pads allowed)
			(copperpour allowed)
			(footprints allowed)
		)
		(placement
			(enabled no)
			(sheetname "")
		)
		(fill
			(thermal_gap 0.5)
			(thermal_bridge_width 0.5)
			(island_removal_mode 0)
		)
		(polygon
			(pts
				(xy 420.69004 -134.704328) (xy 420.69004 -138.430508) (xy 422.08958 -139.830048) (xy 422.08958 -141.044168)
				(xy 422.39692 -141.351508) (xy 423.29862 -141.351508) (xy 423.75582 -140.894308) (xy 425.72432 -140.894308)
				(xy 425.82084 -140.990828) (xy 425.82084 -141.483588) (xy 426.16882 -141.831568) (xy 426.47108 -141.831568)
				(xy 426.87748 -141.425168) (xy 426.87748 -141.219428) (xy 427.36008 -141.219428) (xy 427.46676 -141.326108)
				(xy 427.46676 -142.169388) (xy 427.09592 -142.540228) (xy 427.09592 -143.779748) (xy 427.59884 -144.282668)
				(xy 427.81728 -144.282668) (xy 428.3456 -143.754348) (xy 428.3456 -139.835128) (xy 430.73574 -137.444988)
				(xy 430.73574 -134.272528) (xy 429.10252 -132.639308) (xy 425.37888 -132.639308) (xy 425.37888 -131.963668)
				(xy 425.24934 -131.834128) (xy 424.51782 -131.834128) (xy 423.71264 -132.639308) (xy 422.75506 -132.639308)
			)
		)
	)
	(zone
		(layer "F.Cu")
		(hatch none 0.5)
		(connect_pads
			(clearance 0)
		)
		(min_thickness 0.25)
		(keepout
			(tracks allowed)
			(vias allowed)
			(pads allowed)
			(copperpour allowed)
			(footprints allowed)
		)
		(placement
			(enabled no)
			(sheetname "")
		)
		(fill
			(thermal_gap 0.5)
			(thermal_bridge_width 0.5)
			(island_removal_mode 0)
		)
		(polygon
			(pts
				(xy 59.822842 -214.96655) (xy 59.822842 -214.522812) (xy 62.147958 -214.522812) (xy 62.147958 -214.96655)
			)
		)
	)
	(zone
		(layer "F.Cu")
		(hatch none 0.5)
		(connect_pads
			(clearance 0)
		)
		(min_thickness 0.25)
		(keepout
			(tracks allowed)
			(vias allowed)
			(pads allowed)
			(copperpour allowed)
			(footprints allowed)
		)
		(placement
			(enabled no)
			(sheetname "")
		)
		(fill
			(thermal_gap 0.5)
			(thermal_bridge_width 0.5)
			(island_removal_mode 0)
		)
		(polygon
			(pts
				(xy 386.70738 -221.739968) (xy 386.9944 -221.739968) (xy 387.02488 -221.709488) (xy 387.02488 -221.082108)
				(xy 386.93852 -220.995748) (xy 386.75056 -220.995748) (xy 386.6769 -221.069408) (xy 386.6769 -221.709488)
			)
		)
	)
	(zone
		(layer "F.Cu")
		(hatch none 0.5)
		(connect_pads
			(clearance 0)
		)
		(min_thickness 0.25)
		(keepout
			(tracks allowed)
			(vias allowed)
			(pads allowed)
			(copperpour allowed)
			(footprints allowed)
		)
		(placement
			(enabled no)
			(sheetname "")
		)
		(fill
			(thermal_gap 0.5)
			(thermal_bridge_width 0.5)
			(island_removal_mode 0)
		)
		(polygon
			(pts
				(xy 424.919394 -315.776356) (xy 426.951394 -315.776356) (xy 426.951394 -316.004956) (xy 424.919394 -316.004956)
				(xy 424.78325 -316.004956) (xy 424.73626 -316.004956) (xy 424.73626 -315.776356) (xy 424.78325 -315.776356)
			)
		)
	)
	(zone
		(layer "F.Cu")
		(hatch none 0.5)
		(connect_pads
			(clearance 0)
		)
		(min_thickness 0.25)
		(keepout
			(tracks allowed)
			(vias allowed)
			(pads allowed)
			(copperpour allowed)
			(footprints allowed)
		)
		(placement
			(enabled no)
			(sheetname "")
		)
		(fill
			(thermal_gap 0.5)
			(thermal_bridge_width 0.5)
			(island_removal_mode 0)
		)
		(polygon
			(pts
				(xy 192.066926 -240.976404) (xy 194.098926 -240.976404) (xy 194.098926 -240.97869) (xy 194.277742 -240.97869)
				(xy 194.277742 -241.215926) (xy 194.415664 -241.215926) (xy 194.458844 -241.259106) (xy 194.458844 -241.391948)
				(xy 194.458844 -241.695986) (xy 194.3862 -241.76863) (xy 191.845946 -241.76863) (xy 191.704722 -241.627406)
				(xy 191.704722 -241.430302) (xy 191.786256 -241.348768) (xy 191.786256 -240.976404) (xy 191.883792 -240.976404)
				(xy 191.930782 -240.976404)
			)
		)
	)
	(zone
		(layer "F.Cu")
		(hatch none 0.5)
		(connect_pads
			(clearance 0)
		)
		(min_thickness 0.25)
		(keepout
			(tracks allowed)
			(vias allowed)
			(pads allowed)
			(copperpour allowed)
			(footprints allowed)
		)
		(placement
			(enabled no)
			(sheetname "")
		)
		(fill
			(thermal_gap 0.5)
			(thermal_bridge_width 0.5)
			(island_removal_mode 0)
		)
		(polygon
			(pts
				(xy 439.77814 -29.690568) (xy 439.77814 -30.754828) (xy 440.15152 -31.128208) (xy 440.45378 -31.128208)
				(xy 441.08878 -30.493208) (xy 441.08878 -29.472128) (xy 440.76366 -29.147008) (xy 440.3217 -29.147008)
			)
		)
	)
	(zone
		(layer "F.Cu")
		(hatch none 0.5)
		(connect_pads
			(clearance 0)
		)
		(min_thickness 0.25)
		(keepout
			(tracks allowed)
			(vias allowed)
			(pads allowed)
			(copperpour allowed)
			(footprints allowed)
		)
		(placement
			(enabled no)
			(sheetname "")
		)
		(fill
			(thermal_gap 0.5)
			(thermal_bridge_width 0.5)
			(island_removal_mode 0)
		)
		(polygon
			(pts
				(xy 56.37911 -310.166512) (xy 56.37911 -309.722774) (xy 58.704226 -309.722774) (xy 58.704226 -310.166512)
			)
		)
	)
	(zone
		(layer "F.Cu")
		(hatch none 0.5)
		(connect_pads
			(clearance 0)
		)
		(min_thickness 0.25)
		(keepout
			(tracks allowed)
			(vias allowed)
			(pads allowed)
			(copperpour allowed)
			(footprints allowed)
		)
		(placement
			(enabled no)
			(sheetname "")
		)
		(fill
			(thermal_gap 0.5)
			(thermal_bridge_width 0.5)
			(island_removal_mode 0)
		)
		(polygon
			(pts
				(xy 409.831794 -219.104972) (xy 409.831794 -218.876372) (xy 411.863794 -218.876372) (xy 411.863794 -219.104972)
			)
		)
	)
	(zone
		(layer "F.Cu")
		(hatch none 0.5)
		(connect_pads
			(clearance 0)
		)
		(min_thickness 0.25)
		(keepout
			(tracks not_allowed)
			(vias allowed)
			(pads allowed)
			(copperpour not_allowed)
			(footprints allowed)
		)
		(placement
			(enabled no)
			(sheetname "")
		)
		(fill
			(thermal_gap 0.5)
			(thermal_bridge_width 0.5)
			(island_removal_mode 0)
		)
		(polygon
			(pts
				(arc
					(start 265.895328 -51.999896)
					(mid 268.645386 -49.249838)
					(end 271.395444 -51.999896)
				)
				(arc
					(start 271.395444 -51.999896)
					(mid 268.645386 -54.749954)
					(end 265.895328 -51.999896)
				)
			)
		)
	)
	(zone
		(layer "F.Cu")
		(hatch none 0.5)
		(connect_pads
			(clearance 0)
		)
		(min_thickness 0.25)
		(keepout
			(tracks allowed)
			(vias allowed)
			(pads allowed)
			(copperpour allowed)
			(footprints allowed)
		)
		(placement
			(enabled no)
			(sheetname "")
		)
		(fill
			(thermal_gap 0.5)
			(thermal_bridge_width 0.5)
			(island_removal_mode 0)
		)
		(polygon
			(pts
				(xy 41.29151 -252.366526) (xy 41.29151 -251.922788) (xy 43.616626 -251.922788) (xy 43.616626 -252.366526)
				(xy 43.616626 -252.888496) (xy 41.29151 -252.888496)
			)
		)
	)
	(zone
		(layer "F.Cu")
		(hatch none 0.5)
		(connect_pads
			(clearance 0)
		)
		(min_thickness 0.25)
		(keepout
			(tracks allowed)
			(vias allowed)
			(pads allowed)
			(copperpour allowed)
			(footprints allowed)
		)
		(placement
			(enabled no)
			(sheetname "")
		)
		(fill
			(thermal_gap 0.5)
			(thermal_bridge_width 0.5)
			(island_removal_mode 0)
		)
		(polygon
			(pts
				(xy 44.735242 -277.866602) (xy 44.735242 -277.422864) (xy 47.060358 -277.422864) (xy 47.060358 -277.866602)
			)
		)
	)
	(zone
		(layer "F.Cu")
		(hatch none 0.5)
		(connect_pads
			(clearance 0)
		)
		(min_thickness 0.25)
		(keepout
			(tracks allowed)
			(vias allowed)
			(pads allowed)
			(copperpour allowed)
			(footprints allowed)
		)
		(placement
			(enabled no)
			(sheetname "")
		)
		(fill
			(thermal_gap 0.5)
			(thermal_bridge_width 0.5)
			(island_removal_mode 0)
		)
		(polygon
			(pts
				(xy 11.11631 -276.16658) (xy 11.11631 -275.722842) (xy 13.441426 -275.722842) (xy 13.441426 -276.16658)
			)
		)
	)
	(zone
		(layer "F.Cu")
		(hatch none 0.5)
		(connect_pads
			(clearance 0)
		)
		(min_thickness 0.25)
		(keepout
			(tracks allowed)
			(vias allowed)
			(pads allowed)
			(copperpour allowed)
			(footprints allowed)
		)
		(placement
			(enabled no)
			(sheetname "")
		)
		(fill
			(thermal_gap 0.5)
			(thermal_bridge_width 0.5)
			(island_removal_mode 0)
		)
		(polygon
			(pts
				(xy 207.154526 -258.826254) (xy 209.186526 -258.826254) (xy 209.186526 -259.054854) (xy 207.154526 -259.054854)
				(xy 206.978758 -259.054854) (xy 206.978758 -258.826254)
			)
		)
	)
	(zone
		(layer "F.Cu")
		(hatch none 0.5)
		(connect_pads
			(clearance 0)
		)
		(min_thickness 0.25)
		(keepout
			(tracks allowed)
			(vias allowed)
			(pads allowed)
			(copperpour allowed)
			(footprints allowed)
		)
		(placement
			(enabled no)
			(sheetname "")
		)
		(fill
			(thermal_gap 0.5)
			(thermal_bridge_width 0.5)
			(island_removal_mode 0)
		)
		(polygon
			(pts
				(xy 262.50011 -215.816434) (xy 262.50011 -215.372696) (xy 264.825226 -215.372696) (xy 264.825226 -215.816434)
			)
		)
	)
	(zone
		(layer "F.Cu")
		(hatch none 0.5)
		(connect_pads
			(clearance 0)
		)
		(min_thickness 0.25)
		(keepout
			(tracks allowed)
			(vias allowed)
			(pads allowed)
			(copperpour allowed)
			(footprints allowed)
		)
		(placement
			(enabled no)
			(sheetname "")
		)
		(fill
			(thermal_gap 0.5)
			(thermal_bridge_width 0.5)
			(island_removal_mode 0)
		)
		(polygon
			(pts
				(xy 157.791658 -286.254952) (xy 157.791658 -286.026352) (xy 159.823658 -286.026352) (xy 159.823658 -286.254952)
			)
		)
	)
	(zone
		(layer "F.Cu")
		(hatch none 0.5)
		(connect_pads
			(clearance 0)
		)
		(min_thickness 0.25)
		(keepout
			(tracks allowed)
			(vias allowed)
			(pads allowed)
			(copperpour allowed)
			(footprints not_allowed)
		)
		(placement
			(enabled no)
			(sheetname "")
		)
		(fill
			(thermal_gap 0.5)
			(thermal_bridge_width 0.5)
			(island_removal_mode 0)
		)
		(polygon
			(pts
				(xy 168.283128 -58.97499) (xy 178.433222 -58.97499) (xy 178.433222 -35.124898) (xy 168.283128 -35.124898)
			)
		)
	)
	(zone
		(layer "F.Cu")
		(hatch none 0.5)
		(connect_pads
			(clearance 0)
		)
		(min_thickness 0.25)
		(keepout
			(tracks allowed)
			(vias allowed)
			(pads allowed)
			(copperpour allowed)
			(footprints allowed)
		)
		(placement
			(enabled no)
			(sheetname "")
		)
		(fill
			(thermal_gap 0.5)
			(thermal_bridge_width 0.5)
			(island_removal_mode 0)
		)
		(polygon
			(pts
				(xy 161.891726 -228.226366) (xy 163.923726 -228.226366) (xy 163.923726 -228.454966) (xy 161.891726 -228.454966)
				(xy 161.788856 -228.454966) (xy 161.696146 -228.454966) (xy 161.696146 -228.226366) (xy 161.788856 -228.226366)
			)
		)
	)
	(zone
		(layer "F.Cu")
		(hatch none 0.5)
		(connect_pads
			(clearance 0)
		)
		(min_thickness 0.25)
		(keepout
			(tracks allowed)
			(vias allowed)
			(pads allowed)
			(copperpour allowed)
			(footprints allowed)
		)
		(placement
			(enabled no)
			(sheetname "")
		)
		(fill
			(thermal_gap 0.5)
			(thermal_bridge_width 0.5)
			(island_removal_mode 0)
		)
		(polygon
			(pts
				(xy 405.22906 -181.562248) (xy 405.22906 -177.378868) (xy 407.2255 -177.378868) (xy 407.2255 -181.562248)
			)
		)
	)
	(zone
		(layer "F.Cu")
		(hatch none 0.5)
		(connect_pads
			(clearance 0)
		)
		(min_thickness 0.25)
		(keepout
			(tracks allowed)
			(vias allowed)
			(pads allowed)
			(copperpour allowed)
			(footprints allowed)
		)
		(placement
			(enabled no)
			(sheetname "")
		)
		(fill
			(thermal_gap 0.5)
			(thermal_bridge_width 0.5)
			(island_removal_mode 0)
		)
		(polygon
			(pts
				(xy 133.11378 -25.61082) (xy 133.11378 -23.41118) (xy 134.91464 -23.41118) (xy 134.91464 -25.61082)
			)
		)
	)
	(zone
		(layer "F.Cu")
		(hatch none 0.5)
		(connect_pads
			(clearance 0)
		)
		(min_thickness 0.25)
		(keepout
			(tracks allowed)
			(vias allowed)
			(pads allowed)
			(copperpour allowed)
			(footprints allowed)
		)
		(placement
			(enabled no)
			(sheetname "")
		)
		(fill
			(thermal_gap 0.5)
			(thermal_bridge_width 0.5)
			(island_removal_mode 0)
		)
		(polygon
			(pts
				(xy 29.647642 -205.616556) (xy 29.647642 -205.172818) (xy 31.972758 -205.172818) (xy 31.972758 -205.616556)
			)
		)
	)
	(zone
		(layer "F.Cu")
		(hatch none 0.5)
		(connect_pads
			(clearance 0)
		)
		(min_thickness 0.25)
		(keepout
			(tracks allowed)
			(vias allowed)
			(pads allowed)
			(copperpour allowed)
			(footprints allowed)
		)
		(placement
			(enabled no)
			(sheetname "")
		)
		(fill
			(thermal_gap 0.5)
			(thermal_bridge_width 0.5)
			(island_removal_mode 0)
		)
		(polygon
			(pts
				(xy 307.76291 -295.716452) (xy 307.76291 -295.272714) (xy 310.088026 -295.272714) (xy 310.088026 -295.716452)
			)
		)
	)
	(zone
		(layer "F.Cu")
		(hatch none 0.5)
		(connect_pads
			(clearance 0)
		)
		(min_thickness 0.25)
		(keepout
			(tracks not_allowed)
			(vias allowed)
			(pads allowed)
			(copperpour not_allowed)
			(footprints allowed)
		)
		(placement
			(enabled no)
			(sheetname "")
		)
		(fill
			(thermal_gap 0.5)
			(thermal_bridge_width 0.5)
			(island_removal_mode 0)
		)
		(polygon
			(pts
				(arc
					(start 237.914942 -79.149956)
					(mid 235.89996 -84.949812)
					(end 233.884978 -79.149956)
				)
			)
		)
	)
	(zone
		(layer "F.Cu")
		(hatch none 0.5)
		(connect_pads
			(clearance 0)
		)
		(min_thickness 0.25)
		(keepout
			(tracks allowed)
			(vias allowed)
			(pads allowed)
			(copperpour allowed)
			(footprints allowed)
		)
		(placement
			(enabled no)
			(sheetname "")
		)
		(fill
			(thermal_gap 0.5)
			(thermal_bridge_width 0.5)
			(island_removal_mode 0)
		)
		(polygon
			(pts
				(xy 157.791658 -213.155022) (xy 157.791658 -212.926422) (xy 159.823658 -212.926422) (xy 159.823658 -213.155022)
			)
		)
	)
	(zone
		(layer "F.Cu")
		(hatch none 0.5)
		(connect_pads
			(clearance 0)
		)
		(min_thickness 0.25)
		(keepout
			(tracks allowed)
			(vias allowed)
			(pads allowed)
			(copperpour allowed)
			(footprints not_allowed)
		)
		(placement
			(enabled no)
			(sheetname "")
		)
		(fill
			(thermal_gap 0.5)
			(thermal_bridge_width 0.5)
			(island_removal_mode 0)
		)
		(polygon
			(pts
				(arc
					(start 173.838362 -440.989974)
					(mid 179.749958 -427.600233)
					(end 185.661554 -440.989974)
				)
			)
		)
	)
	(zone
		(layer "F.Cu")
		(hatch none 0.5)
		(connect_pads
			(clearance 0)
		)
		(min_thickness 0.25)
		(keepout
			(tracks allowed)
			(vias allowed)
			(pads allowed)
			(copperpour allowed)
			(footprints allowed)
		)
		(placement
			(enabled no)
			(sheetname "")
		)
		(fill
			(thermal_gap 0.5)
			(thermal_bridge_width 0.5)
			(island_removal_mode 0)
		)
		(polygon
			(pts
				(xy 328.638662 -345.219782) (xy 326.891142 -345.219782) (xy 326.891142 -343.284302) (xy 328.638662 -343.284302)
			)
		)
	)
	(zone
		(layer "F.Cu")
		(hatch none 0.5)
		(connect_pads
			(clearance 0)
		)
		(min_thickness 0.25)
		(keepout
			(tracks allowed)
			(vias allowed)
			(pads allowed)
			(copperpour allowed)
			(footprints allowed)
		)
		(placement
			(enabled no)
			(sheetname "")
		)
		(fill
			(thermal_gap 0.5)
			(thermal_bridge_width 0.5)
			(island_removal_mode 0)
		)
		(polygon
			(pts
				(xy 458.538326 -205.504796) (xy 458.538326 -205.276196) (xy 460.570326 -205.276196) (xy 460.570326 -205.504796)
			)
		)
	)
	(zone
		(layer "F.Cu")
		(hatch none 0.5)
		(connect_pads
			(clearance 0)
		)
		(min_thickness 0.25)
		(keepout
			(tracks allowed)
			(vias allowed)
			(pads allowed)
			(copperpour allowed)
			(footprints allowed)
		)
		(placement
			(enabled no)
			(sheetname "")
		)
		(fill
			(thermal_gap 0.5)
			(thermal_bridge_width 0.5)
			(island_removal_mode 0)
		)
		(polygon
			(pts
				(xy 262.50011 -271.916652) (xy 262.50011 -271.472914) (xy 264.825226 -271.472914) (xy 264.825226 -271.916652)
			)
		)
	)
	(zone
		(layer "F.Cu")
		(hatch none 0.5)
		(connect_pads
			(clearance 0)
		)
		(min_thickness 0.25)
		(keepout
			(tracks not_allowed)
			(vias allowed)
			(pads allowed)
			(copperpour not_allowed)
			(footprints allowed)
		)
		(placement
			(enabled no)
			(sheetname "")
		)
		(fill
			(thermal_gap 0.5)
			(thermal_bridge_width 0.5)
			(island_removal_mode 0)
		)
		(polygon
			(pts
				(xy 64.86906 -9.0424) (xy 65.04432 -9.0424) (xy 65.07226 -9.01446) (xy 65.07226 -7.62) (xy 65.0494 -7.59714)
				(xy 64.87922 -7.59714) (xy 64.8589 -7.61746) (xy 64.8589 -9.03224)
			)
		)
	)
	(zone
		(layer "F.Cu")
		(hatch none 0.5)
		(connect_pads
			(clearance 0)
		)
		(min_thickness 0.25)
		(keepout
			(tracks not_allowed)
			(vias allowed)
			(pads allowed)
			(copperpour not_allowed)
			(footprints allowed)
		)
		(placement
			(enabled no)
			(sheetname "")
		)
		(fill
			(thermal_gap 0.5)
			(thermal_bridge_width 0.5)
			(island_removal_mode 0)
		)
		(polygon
			(pts
				(xy 233.89336 -252.029468) (xy 233.89336 -251.181108) (xy 234.12196 -251.181108) (xy 234.12196 -252.029468)
			)
		)
	)
	(zone
		(layer "F.Cu")
		(hatch none 0.5)
		(connect_pads
			(clearance 0)
		)
		(min_thickness 0.25)
		(keepout
			(tracks not_allowed)
			(vias allowed)
			(pads allowed)
			(copperpour not_allowed)
			(footprints allowed)
		)
		(placement
			(enabled no)
			(sheetname "")
		)
		(fill
			(thermal_gap 0.5)
			(thermal_bridge_width 0.5)
			(island_removal_mode 0)
		)
		(polygon
			(pts
				(xy 430.46904 -125.020578) (xy 434.53304 -125.020578) (xy 434.53304 -124.889768) (xy 434.3654 -124.889768)
				(xy 434.3654 -124.884688) (xy 430.46904 -124.884688)
			)
		)
	)
	(zone
		(layer "F.Cu")
		(hatch none 0.5)
		(connect_pads
			(clearance 0)
		)
		(min_thickness 0.25)
		(keepout
			(tracks allowed)
			(vias allowed)
			(pads allowed)
			(copperpour allowed)
			(footprints allowed)
		)
		(placement
			(enabled no)
			(sheetname "")
		)
		(fill
			(thermal_gap 0.5)
			(thermal_bridge_width 0.5)
			(island_removal_mode 0)
		)
		(polygon
			(pts
				(xy 458.538326 -265.854942) (xy 458.538326 -265.626342) (xy 460.570326 -265.626342) (xy 460.570326 -265.854942)
			)
		)
	)
	(zone
		(layer "F.Cu")
		(hatch none 0.5)
		(connect_pads
			(clearance 0)
		)
		(min_thickness 0.25)
		(keepout
			(tracks allowed)
			(vias allowed)
			(pads allowed)
			(copperpour allowed)
			(footprints allowed)
		)
		(placement
			(enabled no)
			(sheetname "")
		)
		(fill
			(thermal_gap 0.5)
			(thermal_bridge_width 0.5)
			(island_removal_mode 0)
		)
		(polygon
			(pts
				(xy 277.58771 -296.56659) (xy 277.58771 -296.122852) (xy 279.912826 -296.122852) (xy 279.912826 -296.56659)
			)
		)
	)
	(zone
		(layer "F.Cu")
		(hatch none 0.5)
		(connect_pads
			(clearance 0)
		)
		(min_thickness 0.25)
		(keepout
			(tracks allowed)
			(vias allowed)
			(pads allowed)
			(copperpour allowed)
			(footprints allowed)
		)
		(placement
			(enabled no)
			(sheetname "")
		)
		(fill
			(thermal_gap 0.5)
			(thermal_bridge_width 0.5)
			(island_removal_mode 0)
		)
		(polygon
			(pts
				(xy 440.006994 -203.576428) (xy 442.038994 -203.576428) (xy 442.038994 -203.805028) (xy 440.006994 -203.805028)
				(xy 439.87085 -203.805028) (xy 439.82386 -203.805028) (xy 439.82386 -203.576428) (xy 439.87085 -203.576428)
			)
		)
	)
	(zone
		(layer "F.Cu")
		(hatch none 0.5)
		(connect_pads
			(clearance 0)
		)
		(min_thickness 0.25)
		(keepout
			(tracks allowed)
			(vias allowed)
			(pads allowed)
			(copperpour allowed)
			(footprints allowed)
		)
		(placement
			(enabled no)
			(sheetname "")
		)
		(fill
			(thermal_gap 0.5)
			(thermal_bridge_width 0.5)
			(island_removal_mode 0)
		)
		(polygon
			(pts
				(xy 292.67531 -309.316628) (xy 292.67531 -308.87289) (xy 295.000426 -308.87289) (xy 295.000426 -309.316628)
			)
		)
	)
	(zone
		(layer "F.Cu")
		(hatch none 0.5)
		(connect_pads
			(clearance 0)
		)
		(min_thickness 0.25)
		(keepout
			(tracks allowed)
			(vias allowed)
			(pads allowed)
			(copperpour allowed)
			(footprints allowed)
		)
		(placement
			(enabled no)
			(sheetname "")
		)
		(fill
			(thermal_gap 0.5)
			(thermal_bridge_width 0.5)
			(island_removal_mode 0)
		)
		(polygon
			(pts
				(xy 409.831794 -228.226366) (xy 411.863794 -228.226366) (xy 411.863794 -228.454966) (xy 409.831794 -228.454966)
				(xy 409.728924 -228.454966) (xy 409.636214 -228.454966) (xy 409.636214 -228.226366) (xy 409.728924 -228.226366)
			)
		)
	)
	(zone
		(layer "F.Cu")
		(hatch none 0.5)
		(connect_pads
			(clearance 0)
		)
		(min_thickness 0.25)
		(keepout
			(tracks allowed)
			(vias allowed)
			(pads allowed)
			(copperpour allowed)
			(footprints allowed)
		)
		(placement
			(enabled no)
			(sheetname "")
		)
		(fill
			(thermal_gap 0.5)
			(thermal_bridge_width 0.5)
			(island_removal_mode 0)
		)
		(polygon
			(pts
				(xy 372.057422 -333.586582) (xy 368.521742 -333.586582) (xy 368.521742 -331.503782) (xy 372.057422 -331.503782)
			)
		)
	)
	(zone
		(layer "F.Cu")
		(hatch none 0.5)
		(connect_pads
			(clearance 0)
		)
		(min_thickness 0.25)
		(keepout
			(tracks allowed)
			(vias allowed)
			(pads allowed)
			(copperpour allowed)
			(footprints allowed)
		)
		(placement
			(enabled no)
			(sheetname "")
		)
		(fill
			(thermal_gap 0.5)
			(thermal_bridge_width 0.5)
			(island_removal_mode 0)
		)
		(polygon
			(pts
				(xy 158.45282 -42.896536) (xy 157.838902 -42.282618) (xy 159.230568 -40.890952) (xy 159.844486 -41.50487)
			)
		)
	)
	(zone
		(layer "F.Cu")
		(hatch none 0.5)
		(connect_pads
			(clearance 0)
		)
		(min_thickness 0.25)
		(keepout
			(tracks allowed)
			(vias allowed)
			(pads allowed)
			(copperpour allowed)
			(footprints allowed)
		)
		(placement
			(enabled no)
			(sheetname "")
		)
		(fill
			(thermal_gap 0.5)
			(thermal_bridge_width 0.5)
			(island_removal_mode 0)
		)
		(polygon
			(pts
				(xy 276.469348 -238.76635) (xy 274.144232 -238.76635) (xy 274.005802 -238.76635) (xy 274.005802 -237.580424)
				(xy 276.530562 -237.580424) (xy 276.530562 -238.76635)
			)
		)
	)
	(zone
		(layer "F.Cu")
		(hatch none 0.5)
		(connect_pads
			(clearance 0)
		)
		(min_thickness 0.25)
		(keepout
			(tracks allowed)
			(vias allowed)
			(pads allowed)
			(copperpour allowed)
			(footprints allowed)
		)
		(placement
			(enabled no)
			(sheetname "")
		)
		(fill
			(thermal_gap 0.5)
			(thermal_bridge_width 0.5)
			(island_removal_mode 0)
		)
		(polygon
			(pts
				(xy 446.14338 -70.033388) (xy 446.14338 -70.861428) (xy 446.61328 -71.331328) (xy 451.49008 -71.331328)
				(xy 451.51548 -71.305928) (xy 451.51548 -69.972428) (xy 451.4088 -69.865748) (xy 446.31102 -69.865748)
			)
		)
	)
	(zone
		(layer "F.Cu")
		(hatch none 0.5)
		(connect_pads
			(clearance 0)
		)
		(min_thickness 0.25)
		(keepout
			(tracks allowed)
			(vias allowed)
			(pads allowed)
			(copperpour allowed)
			(footprints allowed)
		)
		(placement
			(enabled no)
			(sheetname "")
		)
		(fill
			(thermal_gap 0.5)
			(thermal_bridge_width 0.5)
			(island_removal_mode 0)
		)
		(polygon
			(pts
				(xy 307.76291 -287.216596) (xy 307.76291 -286.772858) (xy 310.088026 -286.772858) (xy 310.088026 -287.216596)
			)
		)
	)
	(zone
		(layer "F.Cu")
		(hatch none 0.5)
		(connect_pads
			(clearance 0)
		)
		(min_thickness 0.25)
		(keepout
			(tracks allowed)
			(vias allowed)
			(pads allowed)
			(copperpour allowed)
			(footprints allowed)
		)
		(placement
			(enabled no)
			(sheetname "")
		)
		(fill
			(thermal_gap 0.5)
			(thermal_bridge_width 0.5)
			(island_removal_mode 0)
		)
		(polygon
			(pts
				(xy 259.056378 -222.616522) (xy 259.056378 -222.172784) (xy 261.381494 -222.172784) (xy 261.381494 -222.616522)
			)
		)
	)
	(zone
		(layer "F.Cu")
		(hatch none 0.5)
		(connect_pads
			(clearance 0)
		)
		(min_thickness 0.25)
		(keepout
			(tracks allowed)
			(vias allowed)
			(pads allowed)
			(copperpour allowed)
			(footprints not_allowed)
		)
		(placement
			(enabled no)
			(sheetname "")
		)
		(fill
			(thermal_gap 0.5)
			(thermal_bridge_width 0.5)
			(island_removal_mode 0)
		)
		(polygon
			(pts
				(arc
					(start 233.849926 -272.50009)
					(mid 236.650022 -269.699994)
					(end 239.450118 -272.50009)
				)
				(arc
					(start 239.450118 -272.50009)
					(mid 236.650022 -275.300186)
					(end 233.849926 -272.50009)
				)
			)
		)
	)
	(zone
		(layer "F.Cu")
		(hatch none 0.5)
		(connect_pads
			(clearance 0)
		)
		(min_thickness 0.25)
		(keepout
			(tracks allowed)
			(vias allowed)
			(pads allowed)
			(copperpour allowed)
			(footprints allowed)
		)
		(placement
			(enabled no)
			(sheetname "")
		)
		(fill
			(thermal_gap 0.5)
			(thermal_bridge_width 0.5)
			(island_removal_mode 0)
		)
		(polygon
			(pts
				(xy 413.275526 -287.954974) (xy 413.275526 -287.726374) (xy 415.307526 -287.726374) (xy 415.307526 -287.954974)
			)
		)
	)
	(zone
		(layer "F.Cu")
		(hatch none 0.5)
		(connect_pads
			(clearance 0)
		)
		(min_thickness 0.25)
		(keepout
			(tracks allowed)
			(vias allowed)
			(pads allowed)
			(copperpour allowed)
			(footprints not_allowed)
		)
		(placement
			(enabled no)
			(sheetname "")
		)
		(fill
			(thermal_gap 0.5)
			(thermal_bridge_width 0.5)
			(island_removal_mode 0)
		)
		(polygon
			(pts
				(arc
					(start 467.035642 -166.236904)
					(mid 467.169437 -166.103844)
					(end 467.300056 -165.967664)
				)
				(arc
					(start 467.300056 -155.032456)
					(mid 453.632554 -158.848486)
					(end 464.59394 -167.860472)
				)
				(xy 464.59394 -166.236904)
			)
		)
	)
	(zone
		(layer "F.Cu")
		(hatch none 0.5)
		(connect_pads
			(clearance 0)
		)
		(min_thickness 0.25)
		(keepout
			(tracks allowed)
			(vias allowed)
			(pads allowed)
			(copperpour allowed)
			(footprints allowed)
		)
		(placement
			(enabled no)
			(sheetname "")
		)
		(fill
			(thermal_gap 0.5)
			(thermal_bridge_width 0.5)
			(island_removal_mode 0)
		)
		(polygon
			(pts
				(xy 307.76291 -213.266528) (xy 307.76291 -212.82279) (xy 310.088026 -212.82279) (xy 310.088026 -213.266528)
			)
		)
	)
	(zone
		(layer "F.Cu")
		(hatch none 0.5)
		(connect_pads
			(clearance 0)
		)
		(min_thickness 0.25)
		(keepout
			(tracks allowed)
			(vias allowed)
			(pads allowed)
			(copperpour allowed)
			(footprints allowed)
		)
		(placement
			(enabled no)
			(sheetname "")
		)
		(fill
			(thermal_gap 0.5)
			(thermal_bridge_width 0.5)
			(island_removal_mode 0)
		)
		(polygon
			(pts
				(xy 41.29151 -297.416474) (xy 41.29151 -296.972736) (xy 43.616626 -296.972736) (xy 43.616626 -297.416474)
			)
		)
	)
	(zone
		(layer "F.Cu")
		(hatch none 0.5)
		(connect_pads
			(clearance 0)
		)
		(min_thickness 0.25)
		(keepout
			(tracks allowed)
			(vias allowed)
			(pads allowed)
			(copperpour allowed)
			(footprints allowed)
		)
		(placement
			(enabled no)
			(sheetname "")
		)
		(fill
			(thermal_gap 0.5)
			(thermal_bridge_width 0.5)
			(island_removal_mode 0)
		)
		(polygon
			(pts
				(xy 289.231578 -313.566556) (xy 289.231578 -313.122818) (xy 291.556694 -313.122818) (xy 291.556694 -313.566556)
			)
		)
	)
	(zone
		(layer "F.Cu")
		(hatch none 0.5)
		(connect_pads
			(clearance 0)
		)
		(min_thickness 0.25)
		(keepout
			(tracks allowed)
			(vias allowed)
			(pads allowed)
			(copperpour allowed)
			(footprints allowed)
		)
		(placement
			(enabled no)
			(sheetname "")
		)
		(fill
			(thermal_gap 0.5)
			(thermal_bridge_width 0.5)
			(island_removal_mode 0)
		)
		(polygon
			(pts
				(xy 458.538326 -216.554812) (xy 458.538326 -216.326212) (xy 460.570326 -216.326212) (xy 460.570326 -216.554812)
			)
		)
	)
	(zone
		(layer "F.Cu")
		(hatch none 0.5)
		(connect_pads
			(clearance 0)
		)
		(min_thickness 0.25)
		(keepout
			(tracks allowed)
			(vias allowed)
			(pads allowed)
			(copperpour allowed)
			(footprints allowed)
		)
		(placement
			(enabled no)
			(sheetname "")
		)
		(fill
			(thermal_gap 0.5)
			(thermal_bridge_width 0.5)
			(island_removal_mode 0)
		)
		(polygon
			(pts
				(xy 52.813966 -165.4937) (xy 54.145942 -165.4937) (xy 54.344824 -165.692582) (xy 54.344824 -167.484552)
				(xy 53.541676 -168.2877) (xy 51.063652 -168.2877) (xy 49.70399 -166.928038) (xy 49.70399 -161.436304)
				(xy 50.843688 -160.296606) (xy 54.764178 -160.296606) (xy 55.395622 -160.92805) (xy 55.395622 -162.644074)
				(xy 54.839108 -163.200588) (xy 52.690522 -163.200588) (xy 52.621942 -163.269168) (xy 52.621942 -165.301676)
			)
		)
	)
	(zone
		(layer "F.Cu")
		(hatch none 0.5)
		(connect_pads
			(clearance 0)
		)
		(min_thickness 0.25)
		(keepout
			(tracks allowed)
			(vias allowed)
			(pads allowed)
			(copperpour allowed)
			(footprints allowed)
		)
		(placement
			(enabled no)
			(sheetname "")
		)
		(fill
			(thermal_gap 0.5)
			(thermal_bridge_width 0.5)
			(island_removal_mode 0)
		)
		(polygon
			(pts
				(xy 424.919394 -289.426396) (xy 426.951394 -289.426396) (xy 426.951394 -289.654996) (xy 424.919394 -289.654996)
				(xy 424.78325 -289.654996) (xy 424.73626 -289.654996) (xy 424.73626 -289.426396) (xy 424.78325 -289.426396)
			)
		)
	)
	(zone
		(layer "F.Cu")
		(hatch none 0.5)
		(connect_pads
			(clearance 0)
		)
		(min_thickness 0.25)
		(keepout
			(tracks allowed)
			(vias allowed)
			(pads allowed)
			(copperpour allowed)
			(footprints allowed)
		)
		(placement
			(enabled no)
			(sheetname "")
		)
		(fill
			(thermal_gap 0.5)
			(thermal_bridge_width 0.5)
			(island_removal_mode 0)
		)
		(polygon
			(pts
				(xy 56.37911 -316.116462) (xy 56.37911 -315.672724) (xy 58.704226 -315.672724) (xy 58.704226 -316.116462)
			)
		)
	)
	(zone
		(layer "F.Cu")
		(hatch none 0.5)
		(connect_pads
			(clearance 0)
		)
		(min_thickness 0.25)
		(keepout
			(tracks allowed)
			(vias allowed)
			(pads allowed)
			(copperpour allowed)
			(footprints allowed)
		)
		(placement
			(enabled no)
			(sheetname "")
		)
		(fill
			(thermal_gap 0.5)
			(thermal_bridge_width 0.5)
			(island_removal_mode 0)
		)
		(polygon
			(pts
				(xy 56.37911 -231.966516) (xy 56.37911 -231.522778) (xy 58.704226 -231.522778) (xy 58.704226 -231.966516)
			)
		)
	)
	(zone
		(layer "F.Cu")
		(hatch none 0.5)
		(connect_pads
			(clearance 0)
		)
		(min_thickness 0.25)
		(keepout
			(tracks allowed)
			(vias allowed)
			(pads allowed)
			(copperpour allowed)
			(footprints allowed)
		)
		(placement
			(enabled no)
			(sheetname "")
		)
		(fill
			(thermal_gap 0.5)
			(thermal_bridge_width 0.5)
			(island_removal_mode 0)
		)
		(polygon
			(pts
				(xy 157.823154 -243.52631) (xy 159.804354 -243.52631) (xy 159.804354 -243.75491) (xy 157.823154 -243.75491)
				(xy 157.59557 -243.75491) (xy 157.59557 -243.52631)
			)
		)
	)
	(zone
		(layer "F.Cu")
		(hatch none 0.5)
		(connect_pads
			(clearance 0)
		)
		(min_thickness 0.25)
		(keepout
			(tracks allowed)
			(vias allowed)
			(pads allowed)
			(copperpour allowed)
			(footprints allowed)
		)
		(placement
			(enabled no)
			(sheetname "")
		)
		(fill
			(thermal_gap 0.5)
			(thermal_bridge_width 0.5)
			(island_removal_mode 0)
		)
		(polygon
			(pts
				(xy 56.407812 -267.66647) (xy 56.407812 -267.222732) (xy 58.668412 -267.222732) (xy 58.668412 -267.66647)
			)
		)
	)
	(zone
		(layer "F.Cu")
		(hatch none 0.5)
		(connect_pads
			(clearance 0)
		)
		(min_thickness 0.25)
		(keepout
			(tracks allowed)
			(vias allowed)
			(pads allowed)
			(copperpour allowed)
			(footprints allowed)
		)
		(placement
			(enabled no)
			(sheetname "")
		)
		(fill
			(thermal_gap 0.5)
			(thermal_bridge_width 0.5)
			(island_removal_mode 0)
		)
		(polygon
			(pts
				(xy 165.335458 -291.355018) (xy 165.335458 -291.126418) (xy 167.367458 -291.126418) (xy 167.367458 -291.355018)
			)
		)
	)
	(zone
		(layer "F.Cu")
		(hatch none 0.5)
		(connect_pads
			(clearance 0)
		)
		(min_thickness 0.25)
		(keepout
			(tracks allowed)
			(vias allowed)
			(pads allowed)
			(copperpour allowed)
			(footprints allowed)
		)
		(placement
			(enabled no)
			(sheetname "")
		)
		(fill
			(thermal_gap 0.5)
			(thermal_bridge_width 0.5)
			(island_removal_mode 0)
		)
		(polygon
			(pts
				(xy 321.902582 -404.802594) (xy 321.902582 -399.959576) (xy 323.787008 -399.959576) (xy 323.787008 -404.802594)
			)
		)
	)
	(zone
		(layer "F.Cu")
		(hatch none 0.5)
		(connect_pads
			(clearance 0)
		)
		(min_thickness 0.25)
		(keepout
			(tracks allowed)
			(vias allowed)
			(pads allowed)
			(copperpour allowed)
			(footprints allowed)
		)
		(placement
			(enabled no)
			(sheetname "")
		)
		(fill
			(thermal_gap 0.5)
			(thermal_bridge_width 0.5)
			(island_removal_mode 0)
		)
		(polygon
			(pts
				(xy 66.186812 -238.766604) (xy 63.977012 -238.766604) (xy 63.582296 -238.766604) (xy 63.582296 -237.560104)
				(xy 66.51752 -237.560104) (xy 66.51752 -238.766604)
			)
		)
	)
	(zone
		(layer "F.Cu")
		(hatch none 0.5)
		(connect_pads
			(clearance 0)
		)
		(min_thickness 0.25)
		(keepout
			(tracks allowed)
			(vias allowed)
			(pads allowed)
			(copperpour allowed)
			(footprints allowed)
		)
		(placement
			(enabled no)
			(sheetname "")
		)
		(fill
			(thermal_gap 0.5)
			(thermal_bridge_width 0.5)
			(island_removal_mode 0)
		)
		(polygon
			(pts
				(xy 180.423058 -236.954822) (xy 180.423058 -236.726222) (xy 182.455058 -236.726222) (xy 182.455058 -236.954822)
			)
		)
	)
	(zone
		(layer "F.Cu")
		(hatch none 0.5)
		(connect_pads
			(clearance 0)
		)
		(min_thickness 0.25)
		(keepout
			(tracks allowed)
			(vias allowed)
			(pads allowed)
			(copperpour allowed)
			(footprints allowed)
		)
		(placement
			(enabled no)
			(sheetname "")
		)
		(fill
			(thermal_gap 0.5)
			(thermal_bridge_width 0.5)
			(island_removal_mode 0)
		)
		(polygon
			(pts
				(xy 210.598258 -208.90484) (xy 210.598258 -208.67624) (xy 212.630258 -208.67624) (xy 212.630258 -208.90484)
			)
		)
	)
	(zone
		(layer "F.Cu")
		(hatch none 0.5)
		(connect_pads
			(clearance 0)
		)
		(min_thickness 0.25)
		(keepout
			(tracks allowed)
			(vias allowed)
			(pads allowed)
			(copperpour allowed)
			(footprints allowed)
		)
		(placement
			(enabled no)
			(sheetname "")
		)
		(fill
			(thermal_gap 0.5)
			(thermal_bridge_width 0.5)
			(island_removal_mode 0)
		)
		(polygon
			(pts
				(xy 176.979326 -211.2264) (xy 179.011326 -211.2264) (xy 179.011326 -211.455) (xy 176.979326 -211.455)
				(xy 176.843182 -211.455) (xy 176.796192 -211.455) (xy 176.796192 -211.2264) (xy 176.843182 -211.2264)
			)
		)
	)
	(zone
		(layer "F.Cu")
		(hatch none 0.5)
		(connect_pads
			(clearance 0)
		)
		(min_thickness 0.25)
		(keepout
			(tracks allowed)
			(vias allowed)
			(pads allowed)
			(copperpour allowed)
			(footprints allowed)
		)
		(placement
			(enabled no)
			(sheetname "")
		)
		(fill
			(thermal_gap 0.5)
			(thermal_bridge_width 0.5)
			(island_removal_mode 0)
		)
		(polygon
			(pts
				(xy 26.20391 -252.366526) (xy 26.20391 -251.922788) (xy 28.529026 -251.922788) (xy 28.529026 -252.366526)
				(xy 28.529026 -252.880876) (xy 26.20391 -252.880876)
			)
		)
	)
	(zone
		(layer "F.Cu")
		(hatch none 0.5)
		(connect_pads
			(clearance 0)
		)
		(min_thickness 0.25)
		(keepout
			(tracks allowed)
			(vias allowed)
			(pads allowed)
			(copperpour allowed)
			(footprints allowed)
		)
		(placement
			(enabled no)
			(sheetname "")
		)
		(fill
			(thermal_gap 0.5)
			(thermal_bridge_width 0.5)
			(island_removal_mode 0)
		)
		(polygon
			(pts
				(xy 259.056378 -238.766604) (xy 259.056378 -238.322866) (xy 261.381494 -238.322866) (xy 261.381494 -238.766604)
			)
		)
	)
	(zone
		(layer "F.Cu")
		(hatch none 0.5)
		(connect_pads
			(clearance 0)
		)
		(min_thickness 0.25)
		(keepout
			(tracks allowed)
			(vias allowed)
			(pads allowed)
			(copperpour allowed)
			(footprints allowed)
		)
		(placement
			(enabled no)
			(sheetname "")
		)
		(fill
			(thermal_gap 0.5)
			(thermal_bridge_width 0.5)
			(island_removal_mode 0)
		)
		(polygon
			(pts
				(xy 11.11631 -316.116462) (xy 11.11631 -315.672724) (xy 13.441426 -315.672724) (xy 13.441426 -316.116462)
			)
		)
	)
	(zone
		(layer "F.Cu")
		(hatch none 0.5)
		(connect_pads
			(clearance 0)
		)
		(min_thickness 0.25)
		(keepout
			(tracks allowed)
			(vias allowed)
			(pads allowed)
			(copperpour allowed)
			(footprints allowed)
		)
		(placement
			(enabled no)
			(sheetname "")
		)
		(fill
			(thermal_gap 0.5)
			(thermal_bridge_width 0.5)
			(island_removal_mode 0)
		)
		(polygon
			(pts
				(xy 11.11631 -271.066514) (xy 11.11631 -270.622776) (xy 13.441426 -270.622776) (xy 13.441426 -271.066514)
			)
		)
	)
	(zone
		(layer "F.Cu")
		(hatch none 0.5)
		(connect_pads
			(clearance 0)
		)
		(min_thickness 0.25)
		(keepout
			(tracks allowed)
			(vias allowed)
			(pads allowed)
			(copperpour allowed)
			(footprints allowed)
		)
		(placement
			(enabled no)
			(sheetname "")
		)
		(fill
			(thermal_gap 0.5)
			(thermal_bridge_width 0.5)
			(island_removal_mode 0)
		)
		(polygon
			(pts
				(xy 428.363126 -222.505016) (xy 428.363126 -222.276416) (xy 430.395126 -222.276416) (xy 430.395126 -222.505016)
			)
		)
	)
	(zone
		(layer "F.Cu")
		(hatch none 0.5)
		(connect_pads
			(clearance 0)
		)
		(min_thickness 0.25)
		(keepout
			(tracks allowed)
			(vias allowed)
			(pads allowed)
			(copperpour allowed)
			(footprints allowed)
		)
		(placement
			(enabled no)
			(sheetname "")
		)
		(fill
			(thermal_gap 0.5)
			(thermal_bridge_width 0.5)
			(island_removal_mode 0)
		)
		(polygon
			(pts
				(xy 41.556686 -355.790754) (xy 39.809166 -355.790754) (xy 39.809166 -353.855274) (xy 41.556686 -353.855274)
			)
		)
	)
	(zone
		(layer "F.Cu")
		(hatch none 0.5)
		(connect_pads
			(clearance 0)
		)
		(min_thickness 0.25)
		(keepout
			(tracks allowed)
			(vias allowed)
			(pads allowed)
			(copperpour allowed)
			(footprints allowed)
		)
		(placement
			(enabled no)
			(sheetname "")
		)
		(fill
			(thermal_gap 0.5)
			(thermal_bridge_width 0.5)
			(island_removal_mode 0)
		)
		(polygon
			(pts
				(xy 157.791658 -199.554846) (xy 157.791658 -199.326246) (xy 159.823658 -199.326246) (xy 159.823658 -199.554846)
			)
		)
	)
	(zone
		(layer "F.Cu")
		(hatch none 0.5)
		(connect_pads
			(clearance 0)
		)
		(min_thickness 0.25)
		(keepout
			(tracks allowed)
			(vias allowed)
			(pads allowed)
			(copperpour allowed)
			(footprints allowed)
		)
		(placement
			(enabled no)
			(sheetname "")
		)
		(fill
			(thermal_gap 0.5)
			(thermal_bridge_width 0.5)
			(island_removal_mode 0)
		)
		(polygon
			(pts
				(xy 56.712612 -404.802594) (xy 56.712612 -399.959576) (xy 58.597038 -399.959576) (xy 58.597038 -404.802594)
			)
		)
	)
	(zone
		(layer "F.Cu")
		(hatch none 0.5)
		(connect_pads
			(clearance 0)
		)
		(min_thickness 0.25)
		(keepout
			(tracks allowed)
			(vias allowed)
			(pads allowed)
			(copperpour allowed)
			(footprints not_allowed)
		)
		(placement
			(enabled no)
			(sheetname "")
		)
		(fill
			(thermal_gap 0.5)
			(thermal_bridge_width 0.5)
			(island_removal_mode 0)
		)
		(polygon
			(pts
				(arc
					(start 200.600056 -22.29993)
					(mid 203.400152 -19.499834)
					(end 206.199994 -22.29993)
				)
				(arc
					(start 206.199994 -22.29993)
					(mid 203.400152 -25.099772)
					(end 200.600056 -22.29993)
				)
			)
		)
	)
	(zone
		(layer "F.Cu")
		(hatch none 0.5)
		(connect_pads
			(clearance 0)
		)
		(min_thickness 0.25)
		(keepout
			(tracks allowed)
			(vias allowed)
			(pads allowed)
			(copperpour allowed)
			(footprints allowed)
		)
		(placement
			(enabled no)
			(sheetname "")
		)
		(fill
			(thermal_gap 0.5)
			(thermal_bridge_width 0.5)
			(island_removal_mode 0)
		)
		(polygon
			(pts
				(xy 277.58771 -282.966414) (xy 277.58771 -282.522676) (xy 279.912826 -282.522676) (xy 279.912826 -282.966414)
			)
		)
	)
	(zone
		(layer "F.Cu")
		(hatch none 0.5)
		(connect_pads
			(clearance 0)
		)
		(min_thickness 0.25)
		(keepout
			(tracks allowed)
			(vias allowed)
			(pads allowed)
			(copperpour allowed)
			(footprints allowed)
		)
		(placement
			(enabled no)
			(sheetname "")
		)
		(fill
			(thermal_gap 0.5)
			(thermal_bridge_width 0.5)
			(island_removal_mode 0)
		)
		(polygon
			(pts
				(xy 14.560042 -231.116632) (xy 14.560042 -230.672894) (xy 16.885158 -230.672894) (xy 16.885158 -231.116632)
			)
		)
	)
	(zone
		(layer "F.Cu")
		(hatch none 0.5)
		(connect_pads
			(clearance 0)
		)
		(min_thickness 0.25)
		(keepout
			(tracks not_allowed)
			(vias allowed)
			(pads allowed)
			(copperpour not_allowed)
			(footprints allowed)
		)
		(placement
			(enabled no)
			(sheetname "")
		)
		(fill
			(thermal_gap 0.5)
			(thermal_bridge_width 0.5)
			(island_removal_mode 0)
		)
		(polygon
			(pts
				(arc
					(start 459.799944 -22.29993)
					(mid 464.799934 -17.29994)
					(end 469.799924 -22.29993)
				)
				(arc
					(start 469.799924 -22.29993)
					(mid 464.799934 -27.29992)
					(end 459.799944 -22.29993)
				)
			)
		)
	)
	(zone
		(layer "F.Cu")
		(hatch none 0.5)
		(connect_pads
			(clearance 0)
		)
		(min_thickness 0.25)
		(keepout
			(tracks not_allowed)
			(vias allowed)
			(pads allowed)
			(copperpour not_allowed)
			(footprints allowed)
		)
		(placement
			(enabled no)
			(sheetname "")
		)
		(fill
			(thermal_gap 0.5)
			(thermal_bridge_width 0.5)
			(island_removal_mode 0)
		)
		(polygon
			(pts
				(xy 38.50132 -391.10412) (xy 38.50132 -390.8806) (xy 41.48836 -390.8806) (xy 41.48836 -391.10412)
			)
		)
	)
	(zone
		(layer "F.Cu")
		(hatch none 0.5)
		(connect_pads
			(clearance 0)
		)
		(min_thickness 0.25)
		(keepout
			(tracks not_allowed)
			(vias allowed)
			(pads allowed)
			(copperpour not_allowed)
			(footprints allowed)
		)
		(placement
			(enabled no)
			(sheetname "")
		)
		(fill
			(thermal_gap 0.5)
			(thermal_bridge_width 0.5)
			(island_removal_mode 0)
		)
		(polygon
			(pts
				(xy 103.11384 -335.753456) (xy 103.356156 -335.753456) (xy 103.356156 -335.689448) (xy 103.11384 -335.689448)
			)
		)
	)
	(zone
		(layer "F.Cu")
		(hatch none 0.5)
		(connect_pads
			(clearance 0)
		)
		(min_thickness 0.25)
		(keepout
			(tracks allowed)
			(vias allowed)
			(pads allowed)
			(copperpour allowed)
			(footprints allowed)
		)
		(placement
			(enabled no)
			(sheetname "")
		)
		(fill
			(thermal_gap 0.5)
			(thermal_bridge_width 0.5)
			(island_removal_mode 0)
		)
		(polygon
			(pts
				(xy 409.831794 -312.604912) (xy 409.831794 -312.376312) (xy 411.863794 -312.376312) (xy 411.863794 -312.604912)
			)
		)
	)
	(zone
		(layer "F.Cu")
		(hatch none 0.5)
		(connect_pads
			(clearance 0)
		)
		(min_thickness 0.25)
		(keepout
			(tracks allowed)
			(vias allowed)
			(pads allowed)
			(copperpour allowed)
			(footprints allowed)
		)
		(placement
			(enabled no)
			(sheetname "")
		)
		(fill
			(thermal_gap 0.5)
			(thermal_bridge_width 0.5)
			(island_removal_mode 0)
		)
		(polygon
			(pts
				(xy 157.791658 -263.305036) (xy 157.791658 -263.076436) (xy 159.823658 -263.076436) (xy 159.823658 -263.305036)
			)
		)
	)
	(zone
		(layer "F.Cu")
		(hatch none 0.5)
		(connect_pads
			(clearance 0)
		)
		(min_thickness 0.25)
		(keepout
			(tracks allowed)
			(vias allowed)
			(pads allowed)
			(copperpour allowed)
			(footprints allowed)
		)
		(placement
			(enabled no)
			(sheetname "")
		)
		(fill
			(thermal_gap 0.5)
			(thermal_bridge_width 0.5)
			(island_removal_mode 0)
		)
		(polygon
			(pts
				(xy 424.919394 -286.026352) (xy 426.951394 -286.026352) (xy 426.951394 -286.254952) (xy 424.919394 -286.254952)
				(xy 424.78325 -286.254952) (xy 424.73626 -286.254952) (xy 424.73626 -286.026352) (xy 424.78325 -286.026352)
			)
		)
	)
	(zone
		(layer "F.Cu")
		(hatch none 0.5)
		(connect_pads
			(clearance 0)
		)
		(min_thickness 0.25)
		(keepout
			(tracks allowed)
			(vias allowed)
			(pads allowed)
			(copperpour allowed)
			(footprints allowed)
		)
		(placement
			(enabled no)
			(sheetname "")
		)
		(fill
			(thermal_gap 0.5)
			(thermal_bridge_width 0.5)
			(island_removal_mode 0)
		)
		(polygon
			(pts
				(xy 86.304374 -335.09966) (xy 86.304374 -339.10524) (xy 86.784434 -339.5853) (xy 88.849454 -339.5853)
				(xy 89.121234 -339.31352) (xy 89.121234 -337.45932) (xy 89.372694 -337.20786) (xy 91.292934 -337.20786)
				(xy 91.709494 -336.7913) (xy 91.709494 -335.30032) (xy 91.061794 -334.65262) (xy 86.751414 -334.65262)
			)
		)
	)
	(zone
		(layer "F.Cu")
		(hatch none 0.5)
		(connect_pads
			(clearance 0)
		)
		(min_thickness 0.25)
		(keepout
			(tracks allowed)
			(vias allowed)
			(pads allowed)
			(copperpour allowed)
			(footprints allowed)
		)
		(placement
			(enabled no)
			(sheetname "")
		)
		(fill
			(thermal_gap 0.5)
			(thermal_bridge_width 0.5)
			(island_removal_mode 0)
		)
		(polygon
			(pts
				(xy 44.735242 -311.01665) (xy 44.735242 -310.572912) (xy 47.060358 -310.572912) (xy 47.060358 -311.01665)
			)
		)
	)
	(zone
		(layer "F.Cu")
		(hatch none 0.5)
		(connect_pads
			(clearance 0)
		)
		(min_thickness 0.25)
		(keepout
			(tracks allowed)
			(vias allowed)
			(pads allowed)
			(copperpour allowed)
			(footprints allowed)
		)
		(placement
			(enabled no)
			(sheetname "")
		)
		(fill
			(thermal_gap 0.5)
			(thermal_bridge_width 0.5)
			(island_removal_mode 0)
		)
		(polygon
			(pts
				(xy 289.231578 -229.41661) (xy 289.231578 -228.972872) (xy 291.556694 -228.972872) (xy 291.556694 -229.41661)
			)
		)
	)
	(zone
		(layer "F.Cu")
		(hatch none 0.5)
		(connect_pads
			(clearance 0)
		)
		(min_thickness 0.25)
		(keepout
			(tracks allowed)
			(vias allowed)
			(pads allowed)
			(copperpour allowed)
			(footprints allowed)
		)
		(placement
			(enabled no)
			(sheetname "")
		)
		(fill
			(thermal_gap 0.5)
			(thermal_bridge_width 0.5)
			(island_removal_mode 0)
		)
		(polygon
			(pts
				(xy 11.11631 -252.366526) (xy 11.11631 -251.922788) (xy 13.441426 -251.922788) (xy 13.441426 -252.366526)
				(xy 13.441426 -252.898656) (xy 11.11631 -252.898656)
			)
		)
	)
	(zone
		(layer "F.Cu")
		(hatch none 0.5)
		(connect_pads
			(clearance 0)
		)
		(min_thickness 0.25)
		(keepout
			(tracks allowed)
			(vias allowed)
			(pads allowed)
			(copperpour allowed)
			(footprints allowed)
		)
		(placement
			(enabled no)
			(sheetname "")
		)
		(fill
			(thermal_gap 0.5)
			(thermal_bridge_width 0.5)
			(island_removal_mode 0)
		)
		(polygon
			(pts
				(xy 147.267168 -404.802594) (xy 147.267168 -399.959576) (xy 149.151594 -399.959576) (xy 149.151594 -404.802594)
			)
		)
	)
	(zone
		(layer "F.Cu")
		(hatch none 0.5)
		(connect_pads
			(clearance 0)
		)
		(min_thickness 0.25)
		(keepout
			(tracks allowed)
			(vias allowed)
			(pads allowed)
			(copperpour allowed)
			(footprints allowed)
		)
		(placement
			(enabled no)
			(sheetname "")
		)
		(fill
			(thermal_gap 0.5)
			(thermal_bridge_width 0.5)
			(island_removal_mode 0)
		)
		(polygon
			(pts
				(xy 180.423058 -280.305002) (xy 180.423058 -280.076402) (xy 182.455058 -280.076402) (xy 182.455058 -280.305002)
			)
		)
	)
	(zone
		(layer "F.Cu")
		(hatch none 0.5)
		(connect_pads
			(clearance 0)
		)
		(min_thickness 0.25)
		(keepout
			(tracks allowed)
			(vias allowed)
			(pads allowed)
			(copperpour allowed)
			(footprints allowed)
		)
		(placement
			(enabled no)
			(sheetname "")
		)
		(fill
			(thermal_gap 0.5)
			(thermal_bridge_width 0.5)
			(island_removal_mode 0)
		)
		(polygon
			(pts
				(xy 458.538326 -273.504914) (xy 458.538326 -273.276314) (xy 460.570326 -273.276314) (xy 460.570326 -273.504914)
			)
		)
	)
	(zone
		(layer "F.Cu")
		(hatch none 0.5)
		(connect_pads
			(clearance 0)
		)
		(min_thickness 0.25)
		(keepout
			(tracks allowed)
			(vias allowed)
			(pads allowed)
			(copperpour allowed)
			(footprints allowed)
		)
		(placement
			(enabled no)
			(sheetname "")
		)
		(fill
			(thermal_gap 0.5)
			(thermal_bridge_width 0.5)
			(island_removal_mode 0)
		)
		(polygon
			(pts
				(xy 195.510658 -208.054956) (xy 195.510658 -207.826356) (xy 197.542658 -207.826356) (xy 197.542658 -208.054956)
			)
		)
	)
	(zone
		(layer "F.Cu")
		(hatch none 0.5)
		(connect_pads
			(clearance 0)
		)
		(min_thickness 0.25)
		(keepout
			(tracks allowed)
			(vias allowed)
			(pads allowed)
			(copperpour allowed)
			(footprints allowed)
		)
		(placement
			(enabled no)
			(sheetname "")
		)
		(fill
			(thermal_gap 0.5)
			(thermal_bridge_width 0.5)
			(island_removal_mode 0)
		)
		(polygon
			(pts
				(xy 157.791658 -208.054956) (xy 157.791658 -207.826356) (xy 159.823658 -207.826356) (xy 159.823658 -208.054956)
			)
		)
	)
	(zone
		(layer "F.Cu")
		(hatch none 0.5)
		(connect_pads
			(clearance 0)
		)
		(min_thickness 0.25)
		(keepout
			(tracks allowed)
			(vias allowed)
			(pads allowed)
			(copperpour allowed)
			(footprints allowed)
		)
		(placement
			(enabled no)
			(sheetname "")
		)
		(fill
			(thermal_gap 0.5)
			(thermal_bridge_width 0.5)
			(island_removal_mode 0)
		)
		(polygon
			(pts
				(xy 161.891726 -312.604912) (xy 161.891726 -312.376312) (xy 163.923726 -312.376312) (xy 163.923726 -312.604912)
			)
		)
	)
	(zone
		(layer "F.Cu")
		(hatch none 0.5)
		(connect_pads
			(clearance 0)
		)
		(min_thickness 0.25)
		(keepout
			(tracks allowed)
			(vias allowed)
			(pads allowed)
			(copperpour allowed)
			(footprints allowed)
		)
		(placement
			(enabled no)
			(sheetname "")
		)
		(fill
			(thermal_gap 0.5)
			(thermal_bridge_width 0.5)
			(island_removal_mode 0)
		)
		(polygon
			(pts
				(xy 46.097698 -20.10791) (xy 46.097698 -16.973296) (xy 47.87646 -16.973296) (xy 47.87646 -20.10791)
			)
		)
	)
	(zone
		(layer "F.Cu")
		(hatch none 0.5)
		(connect_pads
			(clearance 0)
		)
		(min_thickness 0.25)
		(keepout
			(tracks allowed)
			(vias allowed)
			(pads allowed)
			(copperpour allowed)
			(footprints allowed)
		)
		(placement
			(enabled no)
			(sheetname "")
		)
		(fill
			(thermal_gap 0.5)
			(thermal_bridge_width 0.5)
			(island_removal_mode 0)
		)
		(polygon
			(pts
				(xy 29.647642 -290.61664) (xy 29.647642 -290.172902) (xy 31.972758 -290.172902) (xy 31.972758 -290.61664)
			)
		)
	)
	(zone
		(layer "F.Cu")
		(hatch none 0.5)
		(connect_pads
			(clearance 0)
		)
		(min_thickness 0.25)
		(keepout
			(tracks allowed)
			(vias allowed)
			(pads allowed)
			(copperpour allowed)
			(footprints allowed)
		)
		(placement
			(enabled no)
			(sheetname "")
		)
		(fill
			(thermal_gap 0.5)
			(thermal_bridge_width 0.5)
			(island_removal_mode 0)
		)
		(polygon
			(pts
				(xy 56.37911 -265.116564) (xy 56.37911 -264.672826) (xy 58.704226 -264.672826) (xy 58.704226 -265.116564)
			)
		)
	)
	(zone
		(layer "F.Cu")
		(hatch none 0.5)
		(connect_pads
			(clearance 0)
		)
		(min_thickness 0.25)
		(keepout
			(tracks allowed)
			(vias allowed)
			(pads allowed)
			(copperpour allowed)
			(footprints allowed)
		)
		(placement
			(enabled no)
			(sheetname "")
		)
		(fill
			(thermal_gap 0.5)
			(thermal_bridge_width 0.5)
			(island_removal_mode 0)
		)
		(polygon
			(pts
				(xy 349.504 -69.433948) (xy 349.504 -67.935348) (xy 348.69628 -67.935348) (xy 348.615 -68.016628)
				(xy 348.615 -69.433948)
			)
		)
	)
	(zone
		(layer "F.Cu")
		(hatch none 0.5)
		(connect_pads
			(clearance 0)
		)
		(min_thickness 0.25)
		(keepout
			(tracks allowed)
			(vias allowed)
			(pads allowed)
			(copperpour allowed)
			(footprints allowed)
		)
		(placement
			(enabled no)
			(sheetname "")
		)
		(fill
			(thermal_gap 0.5)
			(thermal_bridge_width 0.5)
			(island_removal_mode 0)
		)
		(polygon
			(pts
				(xy 409.831794 -246.304816) (xy 409.831794 -246.076216) (xy 411.863794 -246.076216) (xy 411.863794 -246.304816)
			)
		)
	)
	(zone
		(layer "F.Cu")
		(hatch none 0.5)
		(connect_pads
			(clearance 0)
		)
		(min_thickness 0.25)
		(keepout
			(tracks allowed)
			(vias allowed)
			(pads allowed)
			(copperpour allowed)
			(footprints allowed)
		)
		(placement
			(enabled no)
			(sheetname "")
		)
		(fill
			(thermal_gap 0.5)
			(thermal_bridge_width 0.5)
			(island_removal_mode 0)
		)
		(polygon
			(pts
				(xy 321.62496 -348.971108) (xy 321.62496 -347.495368) (xy 322.89496 -347.495368) (xy 322.89496 -348.971108)
			)
		)
	)
	(zone
		(layer "F.Cu")
		(hatch none 0.5)
		(connect_pads
			(clearance 0)
		)
		(min_thickness 0.25)
		(keepout
			(tracks allowed)
			(vias allowed)
			(pads allowed)
			(copperpour allowed)
			(footprints allowed)
		)
		(placement
			(enabled no)
			(sheetname "")
		)
		(fill
			(thermal_gap 0.5)
			(thermal_bridge_width 0.5)
			(island_removal_mode 0)
		)
		(polygon
			(pts
				(xy 381.75438 -348.264988) (xy 381.75438 -343.733628) (xy 387.92912 -343.733628) (xy 387.92912 -348.264988)
			)
		)
	)
	(zone
		(layer "F.Cu")
		(hatch none 0.5)
		(connect_pads
			(clearance 0)
		)
		(min_thickness 0.25)
		(keepout
			(tracks not_allowed)
			(vias allowed)
			(pads allowed)
			(copperpour not_allowed)
			(footprints allowed)
		)
		(placement
			(enabled no)
			(sheetname "")
		)
		(fill
			(thermal_gap 0.5)
			(thermal_bridge_width 0.5)
			(island_removal_mode 0)
		)
		(polygon
			(pts
				(arc
					(start 10.199878 -435.600094)
					(mid 12.999974 -432.799998)
					(end 15.80007 -435.600094)
				)
				(arc
					(start 15.80007 -435.600094)
					(mid 12.999974 -438.40019)
					(end 10.199878 -435.600094)
				)
			)
		)
	)
	(zone
		(layer "F.Cu")
		(hatch none 0.5)
		(connect_pads
			(clearance 0)
		)
		(min_thickness 0.25)
		(keepout
			(tracks allowed)
			(vias allowed)
			(pads allowed)
			(copperpour allowed)
			(footprints allowed)
		)
		(placement
			(enabled no)
			(sheetname "")
		)
		(fill
			(thermal_gap 0.5)
			(thermal_bridge_width 0.5)
			(island_removal_mode 0)
		)
		(polygon
			(pts
				(xy 356.24262 -36.42614) (xy 356.24262 -34.51352) (xy 359.29316 -34.51352) (xy 359.29316 -36.42614)
			)
		)
	)
	(zone
		(layer "F.Cu")
		(hatch none 0.5)
		(connect_pads
			(clearance 0)
		)
		(min_thickness 0.25)
		(keepout
			(tracks allowed)
			(vias allowed)
			(pads allowed)
			(copperpour allowed)
			(footprints allowed)
		)
		(placement
			(enabled no)
			(sheetname "")
		)
		(fill
			(thermal_gap 0.5)
			(thermal_bridge_width 0.5)
			(island_removal_mode 0)
		)
		(polygon
			(pts
				(xy 424.66133 -319.243202) (xy 424.66133 -316.881002) (xy 427.27753 -316.881002) (xy 427.27753 -319.243202)
			)
		)
	)
	(zone
		(layer "F.Cu")
		(hatch none 0.5)
		(connect_pads
			(clearance 0)
		)
		(min_thickness 0.25)
		(keepout
			(tracks allowed)
			(vias allowed)
			(pads allowed)
			(copperpour allowed)
			(footprints allowed)
		)
		(placement
			(enabled no)
			(sheetname "")
		)
		(fill
			(thermal_gap 0.5)
			(thermal_bridge_width 0.5)
			(island_removal_mode 0)
		)
		(polygon
			(pts
				(xy 50.78603 -174.22241) (xy 50.78603 -172.47489) (xy 52.72151 -172.47489) (xy 52.72151 -174.22241)
			)
		)
	)
	(zone
		(layer "F.Cu")
		(hatch none 0.5)
		(connect_pads
			(clearance 0)
		)
		(min_thickness 0.25)
		(keepout
			(tracks allowed)
			(vias allowed)
			(pads allowed)
			(copperpour allowed)
			(footprints allowed)
		)
		(placement
			(enabled no)
			(sheetname "")
		)
		(fill
			(thermal_gap 0.5)
			(thermal_bridge_width 0.5)
			(island_removal_mode 0)
		)
		(polygon
			(pts
				(xy 14.560042 -227.716588) (xy 14.560042 -227.27285) (xy 16.885158 -227.27285) (xy 16.885158 -227.716588)
			)
		)
	)
	(zone
		(layer "F.Cu")
		(hatch none 0.5)
		(connect_pads
			(clearance 0)
		)
		(min_thickness 0.25)
		(keepout
			(tracks allowed)
			(vias allowed)
			(pads allowed)
			(copperpour allowed)
			(footprints allowed)
		)
		(placement
			(enabled no)
			(sheetname "")
		)
		(fill
			(thermal_gap 0.5)
			(thermal_bridge_width 0.5)
			(island_removal_mode 0)
		)
		(polygon
			(pts
				(xy 207.154526 -300.476412) (xy 209.186526 -300.476412) (xy 209.186526 -300.705012) (xy 207.154526 -300.705012)
				(xy 207.018382 -300.705012) (xy 206.971392 -300.705012) (xy 206.971392 -300.476412) (xy 207.018382 -300.476412)
			)
		)
	)
	(zone
		(layer "F.Cu")
		(hatch none 0.5)
		(connect_pads
			(clearance 0)
		)
		(min_thickness 0.25)
		(keepout
			(tracks allowed)
			(vias allowed)
			(pads allowed)
			(copperpour allowed)
			(footprints allowed)
		)
		(placement
			(enabled no)
			(sheetname "")
		)
		(fill
			(thermal_gap 0.5)
			(thermal_bridge_width 0.5)
			(island_removal_mode 0)
		)
		(polygon
			(pts
				(xy 11.11631 -205.616556) (xy 11.11631 -205.172818) (xy 13.441426 -205.172818) (xy 13.441426 -205.616556)
			)
		)
	)
	(zone
		(layer "F.Cu")
		(hatch none 0.5)
		(connect_pads
			(clearance 0)
		)
		(min_thickness 0.25)
		(keepout
			(tracks allowed)
			(vias allowed)
			(pads allowed)
			(copperpour allowed)
			(footprints allowed)
		)
		(placement
			(enabled no)
			(sheetname "")
		)
		(fill
			(thermal_gap 0.5)
			(thermal_bridge_width 0.5)
			(island_removal_mode 0)
		)
		(polygon
			(pts
				(xy 195.510658 -213.155022) (xy 195.510658 -212.926422) (xy 197.542658 -212.926422) (xy 197.542658 -213.155022)
			)
		)
	)
	(zone
		(layer "F.Cu")
		(hatch none 0.5)
		(connect_pads
			(clearance 0)
		)
		(min_thickness 0.25)
		(keepout
			(tracks allowed)
			(vias allowed)
			(pads allowed)
			(copperpour allowed)
			(footprints allowed)
		)
		(placement
			(enabled no)
			(sheetname "")
		)
		(fill
			(thermal_gap 0.5)
			(thermal_bridge_width 0.5)
			(island_removal_mode 0)
		)
		(polygon
			(pts
				(xy 195.510658 -205.504796) (xy 195.510658 -205.276196) (xy 197.542658 -205.276196) (xy 197.542658 -205.504796)
			)
		)
	)
	(zone
		(layer "F.Cu")
		(hatch none 0.5)
		(connect_pads
			(clearance 0)
		)
		(min_thickness 0.25)
		(keepout
			(tracks allowed)
			(vias allowed)
			(pads allowed)
			(copperpour allowed)
			(footprints allowed)
		)
		(placement
			(enabled no)
			(sheetname "")
		)
		(fill
			(thermal_gap 0.5)
			(thermal_bridge_width 0.5)
			(island_removal_mode 0)
		)
		(polygon
			(pts
				(xy 197.553834 -274.35683) (xy 195.521834 -274.35683) (xy 195.521834 -274.354544) (xy 195.343018 -274.354544)
				(xy 195.343018 -274.117308) (xy 195.206366 -273.980656) (xy 195.200778 -273.980656) (xy 195.161916 -273.941794)
				(xy 195.161916 -273.941286) (xy 195.161916 -273.718274) (xy 195.315586 -273.564604) (xy 197.774814 -273.564604)
				(xy 197.916038 -273.705828) (xy 197.916038 -273.902932) (xy 197.834504 -273.984466) (xy 197.750684 -274.068286)
				(xy 197.750684 -274.35683) (xy 197.736968 -274.35683) (xy 197.689978 -274.35683)
			)
		)
	)
	(zone
		(layer "F.Cu")
		(hatch none 0.5)
		(connect_pads
			(clearance 0)
		)
		(min_thickness 0.25)
		(keepout
			(tracks allowed)
			(vias allowed)
			(pads allowed)
			(copperpour allowed)
			(footprints allowed)
		)
		(placement
			(enabled no)
			(sheetname "")
		)
		(fill
			(thermal_gap 0.5)
			(thermal_bridge_width 0.5)
			(island_removal_mode 0)
		)
		(polygon
			(pts
				(xy 11.11631 -220.066616) (xy 11.11631 -219.622878) (xy 13.441426 -219.622878) (xy 13.441426 -220.066616)
			)
		)
	)
	(zone
		(layer "F.Cu")
		(hatch none 0.5)
		(connect_pads
			(clearance 0)
		)
		(min_thickness 0.25)
		(keepout
			(tracks allowed)
			(vias allowed)
			(pads allowed)
			(copperpour allowed)
			(footprints allowed)
		)
		(placement
			(enabled no)
			(sheetname "")
		)
		(fill
			(thermal_gap 0.5)
			(thermal_bridge_width 0.5)
			(island_removal_mode 0)
		)
		(polygon
			(pts
				(xy 105.404666 -365.457232) (xy 114.005106 -365.457232) (xy 116.880386 -362.581952) (xy 116.880386 -353.460812)
				(xy 114.469926 -351.050352) (xy 101.808026 -351.050352) (xy 101.330506 -351.527872) (xy 101.330506 -359.371392)
				(xy 102.186486 -360.227372) (xy 104.246426 -360.227372) (xy 104.304846 -360.285792) (xy 104.304846 -364.357412)
			)
		)
	)
	(zone
		(layer "F.Cu")
		(hatch none 0.5)
		(connect_pads
			(clearance 0)
		)
		(min_thickness 0.25)
		(keepout
			(tracks allowed)
			(vias allowed)
			(pads allowed)
			(copperpour allowed)
			(footprints allowed)
		)
		(placement
			(enabled no)
			(sheetname "")
		)
		(fill
			(thermal_gap 0.5)
			(thermal_bridge_width 0.5)
			(island_removal_mode 0)
		)
		(polygon
			(pts
				(xy 443.450726 -235.876338) (xy 445.482726 -235.876338) (xy 445.482726 -235.878624) (xy 445.661542 -235.878624)
				(xy 445.661542 -236.11586) (xy 445.842644 -236.296962) (xy 445.858138 -236.312456) (xy 445.858138 -236.501432)
				(xy 445.842644 -236.516926) (xy 445.731646 -236.627924) (xy 445.691006 -236.668564) (xy 443.229746 -236.668564)
				(xy 443.088522 -236.52734) (xy 443.088522 -236.330236) (xy 443.170056 -236.248702) (xy 443.228984 -236.189774)
				(xy 443.228984 -235.876338) (xy 443.267592 -235.876338) (xy 443.314582 -235.876338)
			)
		)
	)
	(zone
		(layer "F.Cu")
		(hatch none 0.5)
		(connect_pads
			(clearance 0)
		)
		(min_thickness 0.25)
		(keepout
			(tracks allowed)
			(vias allowed)
			(pads allowed)
			(copperpour allowed)
			(footprints allowed)
		)
		(placement
			(enabled no)
			(sheetname "")
		)
		(fill
			(thermal_gap 0.5)
			(thermal_bridge_width 0.5)
			(island_removal_mode 0)
		)
		(polygon
			(pts
				(xy 277.58771 -218.366594) (xy 277.58771 -217.922856) (xy 279.912826 -217.922856) (xy 279.912826 -218.366594)
			)
		)
	)
	(zone
		(layer "F.Cu")
		(hatch none 0.5)
		(connect_pads
			(clearance 0)
		)
		(min_thickness 0.25)
		(keepout
			(tracks allowed)
			(vias allowed)
			(pads allowed)
			(copperpour allowed)
			(footprints allowed)
		)
		(placement
			(enabled no)
			(sheetname "")
		)
		(fill
			(thermal_gap 0.5)
			(thermal_bridge_width 0.5)
			(island_removal_mode 0)
		)
		(polygon
			(pts
				(xy 84.260182 -237.469426) (xy 84.463128 -237.672372) (xy 84.506308 -237.672372) (xy 84.950046 -237.228634)
				(xy 84.950046 -237.10646) (xy 84.81695 -236.973618) (xy 84.71281 -236.973618) (xy 84.260182 -237.426246)
			)
		)
	)
	(zone
		(layer "F.Cu")
		(hatch none 0.5)
		(connect_pads
			(clearance 0)
		)
		(min_thickness 0.25)
		(keepout
			(tracks allowed)
			(vias allowed)
			(pads allowed)
			(copperpour allowed)
			(footprints allowed)
		)
		(placement
			(enabled no)
			(sheetname "")
		)
		(fill
			(thermal_gap 0.5)
			(thermal_bridge_width 0.5)
			(island_removal_mode 0)
		)
		(polygon
			(pts
				(xy 405.731726 -267.554964) (xy 405.731726 -267.326364) (xy 407.763726 -267.326364) (xy 407.763726 -267.554964)
			)
		)
	)
	(zone
		(layer "F.Cu")
		(hatch none 0.5)
		(connect_pads
			(clearance 0)
		)
		(min_thickness 0.25)
		(keepout
			(tracks allowed)
			(vias allowed)
			(pads allowed)
			(copperpour allowed)
			(footprints allowed)
		)
		(placement
			(enabled no)
			(sheetname "")
		)
		(fill
			(thermal_gap 0.5)
			(thermal_bridge_width 0.5)
			(island_removal_mode 0)
		)
		(polygon
			(pts
				(xy 195.510658 -264.15492) (xy 195.510658 -263.92632) (xy 197.542658 -263.92632) (xy 197.542658 -264.15492)
			)
		)
	)
	(zone
		(layer "F.Cu")
		(hatch none 0.5)
		(connect_pads
			(clearance 0)
		)
		(min_thickness 0.25)
		(keepout
			(tracks allowed)
			(vias allowed)
			(pads allowed)
			(copperpour allowed)
			(footprints allowed)
		)
		(placement
			(enabled no)
			(sheetname "")
		)
		(fill
			(thermal_gap 0.5)
			(thermal_bridge_width 0.5)
			(island_removal_mode 0)
		)
		(polygon
			(pts
				(xy 84.229702 -242.310666) (xy 84.432648 -242.513612) (xy 84.475828 -242.513612) (xy 84.919566 -242.069874)
				(xy 84.919566 -241.9477) (xy 84.78647 -241.814858) (xy 84.68233 -241.814858) (xy 84.229702 -242.267486)
			)
		)
	)
	(zone
		(layer "F.Cu")
		(hatch none 0.5)
		(connect_pads
			(clearance 0)
		)
		(min_thickness 0.25)
		(keepout
			(tracks allowed)
			(vias allowed)
			(pads allowed)
			(copperpour allowed)
			(footprints allowed)
		)
		(placement
			(enabled no)
			(sheetname "")
		)
		(fill
			(thermal_gap 0.5)
			(thermal_bridge_width 0.5)
			(island_removal_mode 0)
		)
		(polygon
			(pts
				(xy 274.143978 -197.966584) (xy 274.143978 -197.522846) (xy 276.469094 -197.522846) (xy 276.469094 -197.966584)
			)
		)
	)
	(zone
		(layer "F.Cu")
		(hatch none 0.5)
		(connect_pads
			(clearance 0)
		)
		(min_thickness 0.25)
		(keepout
			(tracks allowed)
			(vias allowed)
			(pads allowed)
			(copperpour allowed)
			(footprints allowed)
		)
		(placement
			(enabled no)
			(sheetname "")
		)
		(fill
			(thermal_gap 0.5)
			(thermal_bridge_width 0.5)
			(island_removal_mode 0)
		)
		(polygon
			(pts
				(xy 443.450726 -310.055006) (xy 443.450726 -309.826406) (xy 445.482726 -309.826406) (xy 445.482726 -310.055006)
			)
		)
	)
	(zone
		(layer "F.Cu")
		(hatch none 0.5)
		(connect_pads
			(clearance 0)
		)
		(min_thickness 0.25)
		(keepout
			(tracks allowed)
			(vias allowed)
			(pads allowed)
			(copperpour allowed)
			(footprints allowed)
		)
		(placement
			(enabled no)
			(sheetname "")
		)
		(fill
			(thermal_gap 0.5)
			(thermal_bridge_width 0.5)
			(island_removal_mode 0)
		)
		(polygon
			(pts
				(xy 307.76291 -281.266646) (xy 307.76291 -280.822908) (xy 310.088026 -280.822908) (xy 310.088026 -281.266646)
			)
		)
	)
	(zone
		(layer "F.Cu")
		(hatch none 0.5)
		(connect_pads
			(clearance 0)
		)
		(min_thickness 0.25)
		(keepout
			(tracks allowed)
			(vias allowed)
			(pads allowed)
			(copperpour allowed)
			(footprints allowed)
		)
		(placement
			(enabled no)
			(sheetname "")
		)
		(fill
			(thermal_gap 0.5)
			(thermal_bridge_width 0.5)
			(island_removal_mode 0)
		)
		(polygon
			(pts
				(xy 195.510658 -224.204784) (xy 195.510658 -223.976184) (xy 197.542658 -223.976184) (xy 197.542658 -224.204784)
			)
		)
	)
	(zone
		(layer "F.Cu")
		(hatch none 0.5)
		(connect_pads
			(clearance 0)
		)
		(min_thickness 0.25)
		(keepout
			(tracks allowed)
			(vias allowed)
			(pads allowed)
			(copperpour allowed)
			(footprints allowed)
		)
		(placement
			(enabled no)
			(sheetname "")
		)
		(fill
			(thermal_gap 0.5)
			(thermal_bridge_width 0.5)
			(island_removal_mode 0)
		)
		(polygon
			(pts
				(xy 14.560042 -277.016464) (xy 14.560042 -276.572726) (xy 16.885158 -276.572726) (xy 16.885158 -277.016464)
			)
		)
	)
	(zone
		(layer "F.Cu")
		(hatch none 0.5)
		(connect_pads
			(clearance 0)
		)
		(min_thickness 0.25)
		(keepout
			(tracks allowed)
			(vias allowed)
			(pads allowed)
			(copperpour allowed)
			(footprints allowed)
		)
		(placement
			(enabled no)
			(sheetname "")
		)
		(fill
			(thermal_gap 0.5)
			(thermal_bridge_width 0.5)
			(island_removal_mode 0)
		)
		(polygon
			(pts
				(xy 458.538326 -197.854824) (xy 458.538326 -197.626224) (xy 460.570326 -197.626224) (xy 460.570326 -197.854824)
			)
		)
	)
	(zone
		(layer "F.Cu")
		(hatch none 0.5)
		(connect_pads
			(clearance 0)
		)
		(min_thickness 0.25)
		(keepout
			(tracks allowed)
			(vias allowed)
			(pads allowed)
			(copperpour allowed)
			(footprints allowed)
		)
		(placement
			(enabled no)
			(sheetname "")
		)
		(fill
			(thermal_gap 0.5)
			(thermal_bridge_width 0.5)
			(island_removal_mode 0)
		)
		(polygon
			(pts
				(xy 40.14724 -5.939028) (xy 40.14724 -4.036568) (xy 42.23258 -4.036568) (xy 42.23258 -5.939028)
			)
		)
	)
	(zone
		(layer "F.Cu")
		(hatch none 0.5)
		(connect_pads
			(clearance 0)
		)
		(min_thickness 0.25)
		(keepout
			(tracks allowed)
			(vias allowed)
			(pads allowed)
			(copperpour allowed)
			(footprints allowed)
		)
		(placement
			(enabled no)
			(sheetname "")
		)
		(fill
			(thermal_gap 0.5)
			(thermal_bridge_width 0.5)
			(island_removal_mode 0)
		)
		(polygon
			(pts
				(xy 289.231578 -203.916534) (xy 289.231578 -203.472796) (xy 291.556694 -203.472796) (xy 291.556694 -203.916534)
			)
		)
	)
	(zone
		(layer "F.Cu")
		(hatch none 0.5)
		(connect_pads
			(clearance 0)
		)
		(min_thickness 0.25)
		(keepout
			(tracks allowed)
			(vias allowed)
			(pads allowed)
			(copperpour allowed)
			(footprints allowed)
		)
		(placement
			(enabled no)
			(sheetname "")
		)
		(fill
			(thermal_gap 0.5)
			(thermal_bridge_width 0.5)
			(island_removal_mode 0)
		)
		(polygon
			(pts
				(xy 195.510658 -280.305002) (xy 195.510658 -280.076402) (xy 197.542658 -280.076402) (xy 197.542658 -280.305002)
			)
		)
	)
	(zone
		(layer "F.Cu")
		(hatch none 0.5)
		(connect_pads
			(clearance 0)
		)
		(min_thickness 0.25)
		(keepout
			(tracks allowed)
			(vias allowed)
			(pads allowed)
			(copperpour allowed)
			(footprints allowed)
		)
		(placement
			(enabled no)
			(sheetname "")
		)
		(fill
			(thermal_gap 0.5)
			(thermal_bridge_width 0.5)
			(island_removal_mode 0)
		)
		(polygon
			(pts
				(xy 455.094594 -284.556962) (xy 457.126594 -284.556962) (xy 457.126594 -284.328362) (xy 455.094594 -284.328362)
				(xy 454.963276 -284.328362) (xy 454.937368 -284.328362) (xy 454.937368 -284.556962) (xy 454.963276 -284.556962)
			)
		)
	)
	(zone
		(layer "F.Cu")
		(hatch none 0.5)
		(connect_pads
			(clearance 0)
		)
		(min_thickness 0.25)
		(keepout
			(tracks allowed)
			(vias allowed)
			(pads allowed)
			(copperpour allowed)
			(footprints not_allowed)
		)
		(placement
			(enabled no)
			(sheetname "")
		)
		(fill
			(thermal_gap 0.5)
			(thermal_bridge_width 0.5)
			(island_removal_mode 0)
		)
		(polygon
			(pts
				(xy 230.300022 -63.524892) (xy 238.300006 -63.524892) (xy 238.300006 -41.924986) (xy 237.949994 -41.924986)
				(xy 237.949994 -37.595048) (xy 230.300022 -37.595048) (xy 230.300022 -41.999916) (xy 230.650034 -41.999916)
				(xy 230.650034 -46.999906) (xy 230.300022 -46.999906)
			)
		)
	)
	(zone
		(layer "F.Cu")
		(hatch none 0.5)
		(connect_pads
			(clearance 0)
		)
		(min_thickness 0.25)
		(keepout
			(tracks allowed)
			(vias allowed)
			(pads allowed)
			(copperpour allowed)
			(footprints allowed)
		)
		(placement
			(enabled no)
			(sheetname "")
		)
		(fill
			(thermal_gap 0.5)
			(thermal_bridge_width 0.5)
			(island_removal_mode 0)
		)
		(polygon
			(pts
				(xy 137.8585 -284.899608) (xy 138.14552 -284.899608) (xy 138.176 -284.869128) (xy 138.176 -284.241748)
				(xy 138.08964 -284.155388) (xy 137.90168 -284.155388) (xy 137.82802 -284.229048) (xy 137.82802 -284.869128)
			)
		)
	)
	(zone
		(layer "F.Cu")
		(hatch none 0.5)
		(connect_pads
			(clearance 0)
		)
		(min_thickness 0.25)
		(keepout
			(tracks not_allowed)
			(vias allowed)
			(pads allowed)
			(copperpour not_allowed)
			(footprints allowed)
		)
		(placement
			(enabled no)
			(sheetname "")
		)
		(fill
			(thermal_gap 0.5)
			(thermal_bridge_width 0.5)
			(island_removal_mode 0)
		)
		(polygon
			(pts
				(xy 413.009588 -173.32198) (xy 413.51708 -173.32198) (xy 413.758888 -173.080172) (xy 413.758888 -168.534588)
				(xy 413.546036 -168.321736) (xy 413.009588 -168.321736) (xy 413.009588 -168.612058) (xy 413.465264 -168.612058)
				(xy 413.465264 -173.031658) (xy 413.009588 -173.031658)
			)
		)
	)
	(zone
		(layer "F.Cu")
		(hatch none 0.5)
		(connect_pads
			(clearance 0)
		)
		(min_thickness 0.25)
		(keepout
			(tracks allowed)
			(vias allowed)
			(pads allowed)
			(copperpour allowed)
			(footprints allowed)
		)
		(placement
			(enabled no)
			(sheetname "")
		)
		(fill
			(thermal_gap 0.5)
			(thermal_bridge_width 0.5)
			(island_removal_mode 0)
		)
		(polygon
			(pts
				(xy 259.056378 -304.216562) (xy 259.056378 -303.772824) (xy 261.381494 -303.772824) (xy 261.381494 -304.216562)
			)
		)
	)
	(zone
		(layer "F.Cu")
		(hatch none 0.5)
		(connect_pads
			(clearance 0)
		)
		(min_thickness 0.25)
		(keepout
			(tracks allowed)
			(vias allowed)
			(pads allowed)
			(copperpour allowed)
			(footprints allowed)
		)
		(placement
			(enabled no)
			(sheetname "")
		)
		(fill
			(thermal_gap 0.5)
			(thermal_bridge_width 0.5)
			(island_removal_mode 0)
		)
		(polygon
			(pts
				(xy 405.731726 -248.854976) (xy 405.731726 -248.626376) (xy 407.763726 -248.626376) (xy 407.763726 -248.854976)
			)
		)
	)
	(zone
		(layer "F.Cu")
		(hatch none 0.5)
		(connect_pads
			(clearance 0)
		)
		(min_thickness 0.25)
		(keepout
			(tracks not_allowed)
			(vias allowed)
			(pads allowed)
			(copperpour not_allowed)
			(footprints allowed)
		)
		(placement
			(enabled no)
			(sheetname "")
		)
		(fill
			(thermal_gap 0.5)
			(thermal_bridge_width 0.5)
			(island_removal_mode 0)
		)
		(polygon
			(pts
				(xy 111.274352 -335.364328) (xy 111.516668 -335.364328) (xy 111.516668 -334.322928) (xy 111.274352 -334.322928)
			)
		)
	)
	(zone
		(layer "F.Cu")
		(hatch none 0.5)
		(connect_pads
			(clearance 0)
		)
		(min_thickness 0.25)
		(keepout
			(tracks allowed)
			(vias allowed)
			(pads allowed)
			(copperpour allowed)
			(footprints allowed)
		)
		(placement
			(enabled no)
			(sheetname "")
		)
		(fill
			(thermal_gap 0.5)
			(thermal_bridge_width 0.5)
			(island_removal_mode 0)
		)
		(polygon
			(pts
				(xy 311.84088 -205.616556) (xy 311.84088 -205.172818) (xy 314.15228 -205.172818) (xy 314.15228 -205.616556)
			)
		)
	)
	(zone
		(layer "F.Cu")
		(hatch none 0.5)
		(connect_pads
			(clearance 0)
		)
		(min_thickness 0.25)
		(keepout
			(tracks allowed)
			(vias allowed)
			(pads allowed)
			(copperpour allowed)
			(footprints allowed)
		)
		(placement
			(enabled no)
			(sheetname "")
		)
		(fill
			(thermal_gap 0.5)
			(thermal_bridge_width 0.5)
			(island_removal_mode 0)
		)
		(polygon
			(pts
				(xy 274.143978 -294.866568) (xy 274.143978 -294.42283) (xy 276.469094 -294.42283) (xy 276.469094 -294.866568)
			)
		)
	)
	(zone
		(layer "F.Cu")
		(hatch none 0.5)
		(connect_pads
			(clearance 0)
		)
		(min_thickness 0.25)
		(keepout
			(tracks allowed)
			(vias allowed)
			(pads allowed)
			(copperpour allowed)
			(footprints allowed)
		)
		(placement
			(enabled no)
			(sheetname "")
		)
		(fill
			(thermal_gap 0.5)
			(thermal_bridge_width 0.5)
			(island_removal_mode 0)
		)
		(polygon
			(pts
				(xy 413.275526 -283.704792) (xy 413.275526 -283.476192) (xy 415.307526 -283.476192) (xy 415.307526 -283.704792)
			)
		)
	)
	(zone
		(layer "F.Cu")
		(hatch none 0.5)
		(connect_pads
			(clearance 0)
		)
		(min_thickness 0.25)
		(keepout
			(tracks allowed)
			(vias allowed)
			(pads allowed)
			(copperpour allowed)
			(footprints allowed)
		)
		(placement
			(enabled no)
			(sheetname "")
		)
		(fill
			(thermal_gap 0.5)
			(thermal_bridge_width 0.5)
			(island_removal_mode 0)
		)
		(polygon
			(pts
				(xy 277.58771 -209.0166) (xy 277.58771 -208.572862) (xy 279.912826 -208.572862) (xy 279.912826 -209.0166)
			)
		)
	)
	(zone
		(layer "F.Cu")
		(hatch none 0.5)
		(connect_pads
			(clearance 0)
		)
		(min_thickness 0.25)
		(keepout
			(tracks allowed)
			(vias allowed)
			(pads allowed)
			(copperpour allowed)
			(footprints not_allowed)
		)
		(placement
			(enabled no)
			(sheetname "")
		)
		(fill
			(thermal_gap 0.5)
			(thermal_bridge_width 0.5)
			(island_removal_mode 0)
		)
		(polygon
			(pts
				(xy 157.812994 -339.092032) (xy 216.719912 -339.092032) (xy 216.719912 -331.092048) (xy 157.812994 -331.092048)
			)
		)
	)
	(zone
		(layer "F.Cu")
		(hatch none 0.5)
		(connect_pads
			(clearance 0)
		)
		(min_thickness 0.25)
		(keepout
			(tracks allowed)
			(vias allowed)
			(pads allowed)
			(copperpour allowed)
			(footprints allowed)
		)
		(placement
			(enabled no)
			(sheetname "")
		)
		(fill
			(thermal_gap 0.5)
			(thermal_bridge_width 0.5)
			(island_removal_mode 0)
		)
		(polygon
			(pts
				(xy 41.29151 -230.266494) (xy 41.29151 -229.822756) (xy 43.616626 -229.822756) (xy 43.616626 -230.266494)
			)
		)
	)
	(zone
		(layer "F.Cu")
		(hatch none 0.5)
		(connect_pads
			(clearance 0)
		)
		(min_thickness 0.25)
		(keepout
			(tracks allowed)
			(vias allowed)
			(pads allowed)
			(copperpour allowed)
			(footprints allowed)
		)
		(placement
			(enabled no)
			(sheetname "")
		)
		(fill
			(thermal_gap 0.5)
			(thermal_bridge_width 0.5)
			(island_removal_mode 0)
		)
		(polygon
			(pts
				(xy 428.363126 -282.005024) (xy 428.363126 -281.776424) (xy 430.395126 -281.776424) (xy 430.395126 -282.005024)
			)
		)
	)
	(zone
		(layer "F.Cu")
		(hatch none 0.5)
		(connect_pads
			(clearance 0)
		)
		(min_thickness 0.25)
		(keepout
			(tracks allowed)
			(vias allowed)
			(pads allowed)
			(copperpour allowed)
			(footprints not_allowed)
		)
		(placement
			(enabled no)
			(sheetname "")
		)
		(fill
			(thermal_gap 0.5)
			(thermal_bridge_width 0.5)
			(island_removal_mode 0)
		)
		(polygon
			(pts
				(arc
					(start 233.849926 -192.499996)
					(mid 236.650022 -189.6999)
					(end 239.450118 -192.499996)
				)
				(arc
					(start 239.450118 -192.499996)
					(mid 236.650022 -195.300092)
					(end 233.849926 -192.499996)
				)
			)
		)
	)
	(zone
		(layer "F.Cu")
		(hatch none 0.5)
		(connect_pads
			(clearance 0)
		)
		(min_thickness 0.25)
		(keepout
			(tracks allowed)
			(vias allowed)
			(pads allowed)
			(copperpour allowed)
			(footprints allowed)
		)
		(placement
			(enabled no)
			(sheetname "")
		)
		(fill
			(thermal_gap 0.5)
			(thermal_bridge_width 0.5)
			(island_removal_mode 0)
		)
		(polygon
			(pts
				(xy 405.22398 -172.900848) (xy 405.22398 -168.666668) (xy 407.25598 -168.666668) (xy 407.25598 -172.900848)
			)
		)
	)
	(zone
		(layer "F.Cu")
		(hatch none 0.5)
		(connect_pads
			(clearance 0)
		)
		(min_thickness 0.25)
		(keepout
			(tracks allowed)
			(vias allowed)
			(pads allowed)
			(copperpour allowed)
			(footprints allowed)
		)
		(placement
			(enabled no)
			(sheetname "")
		)
		(fill
			(thermal_gap 0.5)
			(thermal_bridge_width 0.5)
			(island_removal_mode 0)
		)
		(polygon
			(pts
				(xy 157.791658 -268.404848) (xy 157.791658 -268.176248) (xy 159.823658 -268.176248) (xy 159.823658 -268.404848)
			)
		)
	)
	(zone
		(layer "F.Cu")
		(hatch none 0.5)
		(connect_pads
			(clearance 0)
		)
		(min_thickness 0.25)
		(keepout
			(tracks allowed)
			(vias allowed)
			(pads allowed)
			(copperpour allowed)
			(footprints allowed)
		)
		(placement
			(enabled no)
			(sheetname "")
		)
		(fill
			(thermal_gap 0.5)
			(thermal_bridge_width 0.5)
			(island_removal_mode 0)
		)
		(polygon
			(pts
				(xy 48.684688 -319.243456) (xy 48.684688 -316.881256) (xy 51.300888 -316.881256) (xy 51.300888 -319.243456)
			)
		)
	)
	(zone
		(layer "F.Cu")
		(hatch none 0.5)
		(connect_pads
			(clearance 0)
		)
		(min_thickness 0.25)
		(keepout
			(tracks allowed)
			(vias allowed)
			(pads allowed)
			(copperpour allowed)
			(footprints allowed)
		)
		(placement
			(enabled no)
			(sheetname "")
		)
		(fill
			(thermal_gap 0.5)
			(thermal_bridge_width 0.5)
			(island_removal_mode 0)
		)
		(polygon
			(pts
				(xy 443.450726 -213.155022) (xy 443.450726 -212.926422) (xy 445.482726 -212.926422) (xy 445.482726 -213.155022)
			)
		)
	)
	(zone
		(layer "F.Cu")
		(hatch none 0.5)
		(connect_pads
			(clearance 0)
		)
		(min_thickness 0.25)
		(keepout
			(tracks allowed)
			(vias allowed)
			(pads allowed)
			(copperpour allowed)
			(footprints allowed)
		)
		(placement
			(enabled no)
			(sheetname "")
		)
		(fill
			(thermal_gap 0.5)
			(thermal_bridge_width 0.5)
			(island_removal_mode 0)
		)
		(polygon
			(pts
				(xy 259.056378 -264.266426) (xy 259.056378 -263.822688) (xy 261.381494 -263.822688) (xy 261.381494 -264.266426)
			)
		)
	)
	(zone
		(layer "F.Cu")
		(hatch none 0.5)
		(connect_pads
			(clearance 0)
		)
		(min_thickness 0.25)
		(keepout
			(tracks allowed)
			(vias allowed)
			(pads allowed)
			(copperpour allowed)
			(footprints allowed)
		)
		(placement
			(enabled no)
			(sheetname "")
		)
		(fill
			(thermal_gap 0.5)
			(thermal_bridge_width 0.5)
			(island_removal_mode 0)
		)
		(polygon
			(pts
				(xy 44.735242 -305.066446) (xy 44.735242 -304.622708) (xy 47.060358 -304.622708) (xy 47.060358 -305.066446)
			)
		)
	)
	(zone
		(layer "F.Cu")
		(hatch none 0.5)
		(connect_pads
			(clearance 0)
		)
		(min_thickness 0.25)
		(keepout
			(tracks allowed)
			(vias allowed)
			(pads allowed)
			(copperpour allowed)
			(footprints allowed)
		)
		(placement
			(enabled no)
			(sheetname "")
		)
		(fill
			(thermal_gap 0.5)
			(thermal_bridge_width 0.5)
			(island_removal_mode 0)
		)
		(polygon
			(pts
				(xy 262.50011 -205.616556) (xy 262.50011 -205.172818) (xy 264.825226 -205.172818) (xy 264.825226 -205.616556)
			)
		)
	)
	(zone
		(layer "F.Cu")
		(hatch none 0.5)
		(connect_pads
			(clearance 0)
		)
		(min_thickness 0.25)
		(keepout
			(tracks allowed)
			(vias allowed)
			(pads allowed)
			(copperpour allowed)
			(footprints allowed)
		)
		(placement
			(enabled no)
			(sheetname "")
		)
		(fill
			(thermal_gap 0.5)
			(thermal_bridge_width 0.5)
			(island_removal_mode 0)
		)
		(polygon
			(pts
				(xy 259.056378 -282.11653) (xy 259.056378 -281.672792) (xy 261.381494 -281.672792) (xy 261.381494 -282.11653)
			)
		)
	)
	(zone
		(layer "F.Cu")
		(hatch none 0.5)
		(connect_pads
			(clearance 0)
		)
		(min_thickness 0.25)
		(keepout
			(tracks not_allowed)
			(vias allowed)
			(pads allowed)
			(copperpour not_allowed)
			(footprints allowed)
		)
		(placement
			(enabled no)
			(sheetname "")
		)
		(fill
			(thermal_gap 0.5)
			(thermal_bridge_width 0.5)
			(island_removal_mode 0)
		)
		(polygon
			(pts
				(xy 54.9656 -155.527248) (xy 55.64886 -155.527248) (xy 55.64886 -153.977848) (xy 55.192168 -153.977848)
				(xy 55.192168 -154.673554) (xy 55.352696 -154.673554) (xy 55.352696 -155.232354) (xy 54.946296 -155.232354)
				(xy 54.946296 -154.673554) (xy 55.166768 -154.673554) (xy 55.166768 -153.977848) (xy 55.039768 -153.977848)
				(xy 55.039768 -154.433524) (xy 54.5592 -154.433524) (xy 54.5592 -154.67584) (xy 54.65318 -154.67584)
				(xy 54.65318 -155.268168) (xy 54.9656 -155.268168)
			)
		)
	)
	(zone
		(layer "F.Cu")
		(hatch none 0.5)
		(connect_pads
			(clearance 0)
		)
		(min_thickness 0.25)
		(keepout
			(tracks allowed)
			(vias allowed)
			(pads allowed)
			(copperpour allowed)
			(footprints allowed)
		)
		(placement
			(enabled no)
			(sheetname "")
		)
		(fill
			(thermal_gap 0.5)
			(thermal_bridge_width 0.5)
			(island_removal_mode 0)
		)
		(polygon
			(pts
				(xy 428.363126 -217.40495) (xy 428.363126 -217.17635) (xy 430.395126 -217.17635) (xy 430.395126 -217.40495)
			)
		)
	)
	(zone
		(layer "F.Cu")
		(hatch none 0.5)
		(connect_pads
			(clearance 0)
		)
		(min_thickness 0.25)
		(keepout
			(tracks allowed)
			(vias allowed)
			(pads allowed)
			(copperpour allowed)
			(footprints allowed)
		)
		(placement
			(enabled no)
			(sheetname "")
		)
		(fill
			(thermal_gap 0.5)
			(thermal_bridge_width 0.5)
			(island_removal_mode 0)
		)
		(polygon
			(pts
				(xy 458.538326 -293.05504) (xy 458.538326 -292.82644) (xy 460.570326 -292.82644) (xy 460.570326 -293.05504)
			)
		)
	)
	(zone
		(layer "F.Cu")
		(hatch none 0.5)
		(connect_pads
			(clearance 0)
		)
		(min_thickness 0.25)
		(keepout
			(tracks not_allowed)
			(vias allowed)
			(pads allowed)
			(copperpour not_allowed)
			(footprints allowed)
		)
		(placement
			(enabled no)
			(sheetname "")
		)
		(fill
			(thermal_gap 0.5)
			(thermal_bridge_width 0.5)
			(island_removal_mode 0)
		)
		(polygon
			(pts
				(arc
					(start 380.458726 -354.434902)
					(mid 384.458972 -350.434656)
					(end 388.458964 -354.434902)
				)
				(arc
					(start 388.458964 -354.434902)
					(mid 384.458972 -358.434894)
					(end 380.458726 -354.434902)
				)
			)
		)
	)
	(zone
		(layer "F.Cu")
		(hatch none 0.5)
		(connect_pads
			(clearance 0)
		)
		(min_thickness 0.25)
		(keepout
			(tracks allowed)
			(vias allowed)
			(pads allowed)
			(copperpour allowed)
			(footprints allowed)
		)
		(placement
			(enabled no)
			(sheetname "")
		)
		(fill
			(thermal_gap 0.5)
			(thermal_bridge_width 0.5)
			(island_removal_mode 0)
		)
		(polygon
			(pts
				(xy 286.62122 -352.031808) (xy 286.62122 -349.136208) (xy 290.99256 -349.136208) (xy 290.99256 -352.031808)
			)
		)
	)
	(zone
		(layer "F.Cu")
		(hatch none 0.5)
		(connect_pads
			(clearance 0)
		)
		(min_thickness 0.25)
		(keepout
			(tracks not_allowed)
			(vias allowed)
			(pads allowed)
			(copperpour not_allowed)
			(footprints allowed)
		)
		(placement
			(enabled no)
			(sheetname "")
		)
		(fill
			(thermal_gap 0.5)
			(thermal_bridge_width 0.5)
			(island_removal_mode 0)
		)
		(polygon
			(pts
				(arc
					(start 463.799936 -435.59984)
					(mid 458.799946 -440.59983)
					(end 453.799956 -435.59984)
				)
				(arc
					(start 453.799956 -435.59984)
					(mid 458.799946 -430.59985)
					(end 463.799936 -435.59984)
				)
			)
		)
	)
	(zone
		(layer "F.Cu")
		(hatch none 0.5)
		(connect_pads
			(clearance 0)
		)
		(min_thickness 0.25)
		(keepout
			(tracks allowed)
			(vias allowed)
			(pads allowed)
			(copperpour allowed)
			(footprints allowed)
		)
		(placement
			(enabled no)
			(sheetname "")
		)
		(fill
			(thermal_gap 0.5)
			(thermal_bridge_width 0.5)
			(island_removal_mode 0)
		)
		(polygon
			(pts
				(xy 87.63 -287.350708) (xy 87.91702 -287.350708) (xy 87.9475 -287.320228) (xy 87.9475 -286.692848)
				(xy 87.86114 -286.606488) (xy 87.67318 -286.606488) (xy 87.59952 -286.680148) (xy 87.59952 -287.320228)
			)
		)
	)
	(zone
		(layer "F.Cu")
		(hatch none 0.5)
		(connect_pads
			(clearance 0)
		)
		(min_thickness 0.25)
		(keepout
			(tracks allowed)
			(vias allowed)
			(pads allowed)
			(copperpour allowed)
			(footprints allowed)
		)
		(placement
			(enabled no)
			(sheetname "")
		)
		(fill
			(thermal_gap 0.5)
			(thermal_bridge_width 0.5)
			(island_removal_mode 0)
		)
		(polygon
			(pts
				(xy 26.20391 -226.016566) (xy 26.20391 -225.572828) (xy 28.529026 -225.572828) (xy 28.529026 -226.016566)
			)
		)
	)
	(zone
		(layer "F.Cu")
		(hatch none 0.5)
		(connect_pads
			(clearance 0)
		)
		(min_thickness 0.25)
		(keepout
			(tracks not_allowed)
			(vias allowed)
			(pads allowed)
			(copperpour not_allowed)
			(footprints allowed)
		)
		(placement
			(enabled no)
			(sheetname "")
		)
		(fill
			(thermal_gap 0.5)
			(thermal_bridge_width 0.5)
			(island_removal_mode 0)
		)
		(polygon
			(pts
				(xy 299.25264 -412.38678) (xy 299.25264 -411.81274) (xy 299.43298 -411.81274) (xy 299.43298 -412.38678)
			)
		)
	)
	(zone
		(layer "F.Cu")
		(hatch none 0.5)
		(connect_pads
			(clearance 0)
		)
		(min_thickness 0.25)
		(keepout
			(tracks allowed)
			(vias allowed)
			(pads allowed)
			(copperpour allowed)
			(footprints allowed)
		)
		(placement
			(enabled no)
			(sheetname "")
		)
		(fill
			(thermal_gap 0.5)
			(thermal_bridge_width 0.5)
			(island_removal_mode 0)
		)
		(polygon
			(pts
				(xy 434.44668 -182.369968) (xy 431.77968 -182.369968) (xy 430.90846 -182.369968) (xy 429.40986 -180.871368)
				(xy 429.40986 -178.996848) (xy 429.68672 -178.719988) (xy 430.50968 -178.719988) (xy 431.30724 -177.922428)
				(xy 435.51856 -177.922428) (xy 436.49392 -178.897788) (xy 436.49392 -180.655468) (xy 434.77942 -182.369968)
			)
		)
	)
	(zone
		(layer "F.Cu")
		(hatch none 0.5)
		(connect_pads
			(clearance 0)
		)
		(min_thickness 0.25)
		(keepout
			(tracks allowed)
			(vias allowed)
			(pads allowed)
			(copperpour allowed)
			(footprints allowed)
		)
		(placement
			(enabled no)
			(sheetname "")
		)
		(fill
			(thermal_gap 0.5)
			(thermal_bridge_width 0.5)
			(island_removal_mode 0)
		)
		(polygon
			(pts
				(xy 29.647642 -282.966414) (xy 29.647642 -282.522676) (xy 31.972758 -282.522676) (xy 31.972758 -282.966414)
			)
		)
	)
	(zone
		(layer "F.Cu")
		(hatch none 0.5)
		(connect_pads
			(clearance 0)
		)
		(min_thickness 0.25)
		(keepout
			(tracks allowed)
			(vias allowed)
			(pads allowed)
			(copperpour allowed)
			(footprints allowed)
		)
		(placement
			(enabled no)
			(sheetname "")
		)
		(fill
			(thermal_gap 0.5)
			(thermal_bridge_width 0.5)
			(island_removal_mode 0)
		)
		(polygon
			(pts
				(xy 440.006994 -210.376262) (xy 442.038994 -210.376262) (xy 442.038994 -210.604862) (xy 440.006994 -210.604862)
				(xy 439.875676 -210.604862) (xy 439.849768 -210.604862) (xy 439.849768 -210.376262) (xy 439.875676 -210.376262)
			)
		)
	)
	(zone
		(layer "F.Cu")
		(hatch none 0.5)
		(connect_pads
			(clearance 0)
		)
		(min_thickness 0.25)
		(keepout
			(tracks allowed)
			(vias allowed)
			(pads allowed)
			(copperpour allowed)
			(footprints not_allowed)
		)
		(placement
			(enabled no)
			(sheetname "")
		)
		(fill
			(thermal_gap 0.5)
			(thermal_bridge_width 0.5)
			(island_removal_mode 0)
		)
		(polygon
			(pts
				(xy 416.301682 -87.30488) (xy 437.30164 -87.307166) (xy 437.304688 -60.007246) (xy 416.30473 -60.00496)
			)
		)
	)
	(zone
		(layer "F.Cu")
		(hatch none 0.5)
		(connect_pads
			(clearance 0)
		)
		(min_thickness 0.25)
		(keepout
			(tracks allowed)
			(vias allowed)
			(pads allowed)
			(copperpour allowed)
			(footprints allowed)
		)
		(placement
			(enabled no)
			(sheetname "")
		)
		(fill
			(thermal_gap 0.5)
			(thermal_bridge_width 0.5)
			(island_removal_mode 0)
		)
		(polygon
			(pts
				(xy 454.83653 -319.243202) (xy 454.83653 -316.881002) (xy 457.45273 -316.881002) (xy 457.45273 -319.243202)
			)
		)
	)
	(zone
		(layer "F.Cu")
		(hatch none 0.5)
		(connect_pads
			(clearance 0)
		)
		(min_thickness 0.25)
		(keepout
			(tracks allowed)
			(vias allowed)
			(pads allowed)
			(copperpour allowed)
			(footprints not_allowed)
		)
		(placement
			(enabled no)
			(sheetname "")
		)
		(fill
			(thermal_gap 0.5)
			(thermal_bridge_width 0.5)
			(island_removal_mode 0)
		)
		(polygon
			(pts
				(xy 165.357302 -330.091796) (xy 171.457112 -330.091796) (xy 171.457112 -186.09183) (xy 165.357302 -186.09183)
			)
		)
	)
	(zone
		(layer "F.Cu")
		(hatch none 0.5)
		(connect_pads
			(clearance 0)
		)
		(min_thickness 0.25)
		(keepout
			(tracks allowed)
			(vias allowed)
			(pads allowed)
			(copperpour allowed)
			(footprints allowed)
		)
		(placement
			(enabled no)
			(sheetname "")
		)
		(fill
			(thermal_gap 0.5)
			(thermal_bridge_width 0.5)
			(island_removal_mode 0)
		)
		(polygon
			(pts
				(xy 418.252402 -179.46624) (xy 418.252402 -181.21376) (xy 416.316922 -181.21376) (xy 416.316922 -179.46624)
			)
		)
	)
	(zone
		(layer "F.Cu")
		(hatch none 0.5)
		(connect_pads
			(clearance 0)
		)
		(min_thickness 0.25)
		(keepout
			(tracks allowed)
			(vias allowed)
			(pads allowed)
			(copperpour allowed)
			(footprints allowed)
		)
		(placement
			(enabled no)
			(sheetname "")
		)
		(fill
			(thermal_gap 0.5)
			(thermal_bridge_width 0.5)
			(island_removal_mode 0)
		)
		(polygon
			(pts
				(xy 307.76291 -196.266562) (xy 307.76291 -195.822824) (xy 310.088026 -195.822824) (xy 310.088026 -196.266562)
			)
		)
	)
	(zone
		(layer "F.Cu")
		(hatch none 0.5)
		(connect_pads
			(clearance 0)
		)
		(min_thickness 0.25)
		(keepout
			(tracks allowed)
			(vias allowed)
			(pads allowed)
			(copperpour allowed)
			(footprints allowed)
		)
		(placement
			(enabled no)
			(sheetname "")
		)
		(fill
			(thermal_gap 0.5)
			(thermal_bridge_width 0.5)
			(island_removal_mode 0)
		)
		(polygon
			(pts
				(xy 210.598258 -213.155022) (xy 210.598258 -212.926422) (xy 212.630258 -212.926422) (xy 212.630258 -213.155022)
			)
		)
	)
	(zone
		(layer "F.Cu")
		(hatch none 0.5)
		(connect_pads
			(clearance 0)
		)
		(min_thickness 0.25)
		(keepout
			(tracks allowed)
			(vias allowed)
			(pads allowed)
			(copperpour allowed)
			(footprints allowed)
		)
		(placement
			(enabled no)
			(sheetname "")
		)
		(fill
			(thermal_gap 0.5)
			(thermal_bridge_width 0.5)
			(island_removal_mode 0)
		)
		(polygon
			(pts
				(xy 455.094594 -303.25695) (xy 457.126594 -303.25695) (xy 457.126594 -303.02835) (xy 455.094594 -303.02835)
				(xy 454.963276 -303.02835) (xy 454.937368 -303.02835) (xy 454.937368 -303.25695) (xy 454.963276 -303.25695)
			)
		)
	)
	(zone
		(layer "F.Cu")
		(hatch none 0.5)
		(connect_pads
			(clearance 0)
		)
		(min_thickness 0.25)
		(keepout
			(tracks allowed)
			(vias allowed)
			(pads allowed)
			(copperpour allowed)
			(footprints allowed)
		)
		(placement
			(enabled no)
			(sheetname "")
		)
		(fill
			(thermal_gap 0.5)
			(thermal_bridge_width 0.5)
			(island_removal_mode 0)
		)
		(polygon
			(pts
				(xy 180.423058 -197.854824) (xy 180.423058 -197.626224) (xy 182.455058 -197.626224) (xy 182.455058 -197.854824)
			)
		)
	)
	(zone
		(layer "F.Cu")
		(hatch none 0.5)
		(connect_pads
			(clearance 0)
		)
		(min_thickness 0.25)
		(keepout
			(tracks allowed)
			(vias allowed)
			(pads allowed)
			(copperpour allowed)
			(footprints allowed)
		)
		(placement
			(enabled no)
			(sheetname "")
		)
		(fill
			(thermal_gap 0.5)
			(thermal_bridge_width 0.5)
			(island_removal_mode 0)
		)
		(polygon
			(pts
				(xy 192.066926 -263.076436) (xy 194.098926 -263.076436) (xy 194.098926 -263.305036) (xy 192.066926 -263.305036)
				(xy 191.900302 -263.305036) (xy 191.802766 -263.305036) (xy 191.802766 -263.076436) (xy 191.900302 -263.076436)
			)
		)
	)
	(zone
		(layer "F.Cu")
		(hatch none 0.5)
		(connect_pads
			(clearance 0)
		)
		(min_thickness 0.25)
		(keepout
			(tracks allowed)
			(vias allowed)
			(pads allowed)
			(copperpour allowed)
			(footprints allowed)
		)
		(placement
			(enabled no)
			(sheetname "")
		)
		(fill
			(thermal_gap 0.5)
			(thermal_bridge_width 0.5)
			(island_removal_mode 0)
		)
		(polygon
			(pts
				(xy 11.11631 -238.766604) (xy 11.11631 -238.322866) (xy 13.441426 -238.322866) (xy 13.441426 -238.766604)
			)
		)
	)
	(zone
		(layer "F.Cu")
		(hatch none 0.5)
		(connect_pads
			(clearance 0)
		)
		(min_thickness 0.25)
		(keepout
			(tracks allowed)
			(vias allowed)
			(pads allowed)
			(copperpour allowed)
			(footprints allowed)
		)
		(placement
			(enabled no)
			(sheetname "")
		)
		(fill
			(thermal_gap 0.5)
			(thermal_bridge_width 0.5)
			(island_removal_mode 0)
		)
		(polygon
			(pts
				(xy 89.5604 -289.032188) (xy 89.84742 -289.032188) (xy 89.8779 -289.001708) (xy 89.8779 -288.374328)
				(xy 89.79154 -288.287968) (xy 89.60358 -288.287968) (xy 89.52992 -288.361628) (xy 89.52992 -289.001708)
			)
		)
	)
	(zone
		(layer "F.Cu")
		(hatch none 0.5)
		(connect_pads
			(clearance 0)
		)
		(min_thickness 0.25)
		(keepout
			(tracks allowed)
			(vias allowed)
			(pads allowed)
			(copperpour allowed)
			(footprints allowed)
		)
		(placement
			(enabled no)
			(sheetname "")
		)
		(fill
			(thermal_gap 0.5)
			(thermal_bridge_width 0.5)
			(island_removal_mode 0)
		)
		(polygon
			(pts
				(xy 292.67531 -282.966414) (xy 292.67531 -282.522676) (xy 295.000426 -282.522676) (xy 295.000426 -282.966414)
			)
		)
	)
	(zone
		(layer "F.Cu")
		(hatch none 0.5)
		(connect_pads
			(clearance 0)
		)
		(min_thickness 0.25)
		(keepout
			(tracks allowed)
			(vias allowed)
			(pads allowed)
			(copperpour allowed)
			(footprints allowed)
		)
		(placement
			(enabled no)
			(sheetname "")
		)
		(fill
			(thermal_gap 0.5)
			(thermal_bridge_width 0.5)
			(island_removal_mode 0)
		)
		(polygon
			(pts
				(xy 274.143978 -289.766502) (xy 274.143978 -289.322764) (xy 276.469094 -289.322764) (xy 276.469094 -289.766502)
			)
		)
	)
	(zone
		(layer "F.Cu")
		(hatch none 0.5)
		(connect_pads
			(clearance 0)
		)
		(min_thickness 0.25)
		(keepout
			(tracks not_allowed)
			(vias allowed)
			(pads allowed)
			(copperpour not_allowed)
			(footprints allowed)
		)
		(placement
			(enabled no)
			(sheetname "")
		)
		(fill
			(thermal_gap 0.5)
			(thermal_bridge_width 0.5)
			(island_removal_mode 0)
		)
		(polygon
			(pts
				(arc
					(start 450.349874 -435.600094)
					(mid 448.799966 -437.150002)
					(end 447.250058 -435.600094)
				)
				(arc
					(start 447.250058 -435.600094)
					(mid 448.799966 -434.050186)
					(end 450.349874 -435.600094)
				)
			)
		)
	)
	(zone
		(layer "F.Cu")
		(hatch none 0.5)
		(connect_pads
			(clearance 0)
		)
		(min_thickness 0.25)
		(keepout
			(tracks allowed)
			(vias allowed)
			(pads allowed)
			(copperpour allowed)
			(footprints not_allowed)
		)
		(placement
			(enabled no)
			(sheetname "")
		)
		(fill
			(thermal_gap 0.5)
			(thermal_bridge_width 0.5)
			(island_removal_mode 0)
		)
		(polygon
			(pts
				(xy 398.011396 -43.344592) (xy 401.646898 -43.344592) (xy 401.646898 -70.65518) (xy 398.011396 -70.65518)
				(arc
					(start 398.011396 -72.00011)
					(mid 413.011366 -57.00014)
					(end 398.011396 -41.999916)
				)
			)
		)
	)
	(zone
		(layer "F.Cu")
		(hatch none 0.5)
		(connect_pads
			(clearance 0)
		)
		(min_thickness 0.25)
		(keepout
			(tracks allowed)
			(vias allowed)
			(pads allowed)
			(copperpour allowed)
			(footprints allowed)
		)
		(placement
			(enabled no)
			(sheetname "")
		)
		(fill
			(thermal_gap 0.5)
			(thermal_bridge_width 0.5)
			(island_removal_mode 0)
		)
		(polygon
			(pts
				(xy 26.20391 -299.116496) (xy 26.20391 -298.672758) (xy 28.529026 -298.672758) (xy 28.529026 -299.116496)
			)
		)
	)
	(zone
		(layer "F.Cu")
		(hatch none 0.5)
		(connect_pads
			(clearance 0)
		)
		(min_thickness 0.25)
		(keepout
			(tracks allowed)
			(vias allowed)
			(pads allowed)
			(copperpour allowed)
			(footprints allowed)
		)
		(placement
			(enabled no)
			(sheetname "")
		)
		(fill
			(thermal_gap 0.5)
			(thermal_bridge_width 0.5)
			(island_removal_mode 0)
		)
		(polygon
			(pts
				(xy 428.363126 -226.754944) (xy 428.363126 -226.526344) (xy 430.395126 -226.526344) (xy 430.395126 -226.754944)
			)
		)
	)
	(zone
		(layer "F.Cu")
		(hatch none 0.5)
		(connect_pads
			(clearance 0)
		)
		(min_thickness 0.25)
		(keepout
			(tracks allowed)
			(vias allowed)
			(pads allowed)
			(copperpour allowed)
			(footprints not_allowed)
		)
		(placement
			(enabled no)
			(sheetname "")
		)
		(fill
			(thermal_gap 0.5)
			(thermal_bridge_width 0.5)
			(island_removal_mode 0)
		)
		(polygon
			(pts
				(xy 404.753572 -185.091832) (xy 465.659978 -185.091832) (xy 465.659978 -187.661804) (xy 467.300056 -187.661804)
				(xy 467.300056 -182.236872) (xy 464.59394 -182.236872) (xy 464.59394 -168.661842) (xy 399.303494 -168.661842)
				(xy 399.303494 -187.661804) (xy 404.753572 -187.661804)
			)
		)
	)
	(zone
		(layer "F.Cu")
		(hatch none 0.5)
		(connect_pads
			(clearance 0)
		)
		(min_thickness 0.25)
		(keepout
			(tracks allowed)
			(vias allowed)
			(pads allowed)
			(copperpour allowed)
			(footprints allowed)
		)
		(placement
			(enabled no)
			(sheetname "")
		)
		(fill
			(thermal_gap 0.5)
			(thermal_bridge_width 0.5)
			(island_removal_mode 0)
		)
		(polygon
			(pts
				(xy 405.731726 -203.805028) (xy 405.731726 -203.576428) (xy 407.763726 -203.576428) (xy 407.763726 -203.805028)
			)
		)
	)
	(zone
		(layer "F.Cu")
		(hatch none 0.5)
		(connect_pads
			(clearance 0)
		)
		(min_thickness 0.25)
		(keepout
			(tracks allowed)
			(vias allowed)
			(pads allowed)
			(copperpour allowed)
			(footprints allowed)
		)
		(placement
			(enabled no)
			(sheetname "")
		)
		(fill
			(thermal_gap 0.5)
			(thermal_bridge_width 0.5)
			(island_removal_mode 0)
		)
		(polygon
			(pts
				(xy 207.154526 -251.176282) (xy 209.186526 -251.176282) (xy 209.186526 -251.404882) (xy 207.154526 -251.404882)
				(xy 206.987902 -251.404882) (xy 206.987902 -251.176282)
			)
		)
	)
	(zone
		(layer "F.Cu")
		(hatch none 0.5)
		(connect_pads
			(clearance 0)
		)
		(min_thickness 0.25)
		(keepout
			(tracks allowed)
			(vias allowed)
			(pads allowed)
			(copperpour allowed)
			(footprints allowed)
		)
		(placement
			(enabled no)
			(sheetname "")
		)
		(fill
			(thermal_gap 0.5)
			(thermal_bridge_width 0.5)
			(island_removal_mode 0)
		)
		(polygon
			(pts
				(xy 274.143978 -282.11653) (xy 274.143978 -281.672792) (xy 276.469094 -281.672792) (xy 276.469094 -282.11653)
			)
		)
	)
	(zone
		(layer "F.Cu")
		(hatch none 0.5)
		(connect_pads
			(clearance 0)
		)
		(min_thickness 0.25)
		(keepout
			(tracks allowed)
			(vias allowed)
			(pads allowed)
			(copperpour allowed)
			(footprints not_allowed)
		)
		(placement
			(enabled no)
			(sheetname "")
		)
		(fill
			(thermal_gap 0.5)
			(thermal_bridge_width 0.5)
			(island_removal_mode 0)
		)
		(polygon
			(pts
				(xy 354.24999 -418.869876) (xy 365.300006 -418.869876)
				(arc
					(start 365.300006 -430.306988)
					(mid 371.300707 -427.599995)
					(end 377.299982 -430.310036)
				)
				(xy 377.299982 -417.889944) (xy 415.279078 -417.889944) (xy 415.279078 -410.77007) (xy 304.47996 -410.77007)
				(xy 304.47996 -433.07)
				(arc
					(start 301.139352 -433.07)
					(mid 301.446687 -434.318492)
					(end 301.55007 -435.600094)
				)
				(arc
					(start 301.55007 -435.600094)
					(mid 301.009669 -438.490231)
					(end 299.461682 -440.989974)
				)
				(xy 310.20004 -440.989974) (xy 310.20004 -417.889944) (xy 350.499934 -417.889944) (xy 350.499934 -440.989974)
				(xy 354.24999 -440.989974)
			)
		)
	)
	(zone
		(layer "F.Cu")
		(hatch none 0.5)
		(connect_pads
			(clearance 0)
		)
		(min_thickness 0.25)
		(keepout
			(tracks not_allowed)
			(vias allowed)
			(pads allowed)
			(copperpour not_allowed)
			(footprints allowed)
		)
		(placement
			(enabled no)
			(sheetname "")
		)
		(fill
			(thermal_gap 0.5)
			(thermal_bridge_width 0.5)
			(island_removal_mode 0)
		)
		(polygon
			(pts
				(xy 438.768744 -11.992356) (xy 438.944004 -11.992356) (xy 438.971944 -11.964416) (xy 438.971944 -10.569956)
				(xy 438.949084 -10.547096) (xy 438.778904 -10.547096) (xy 438.758584 -10.567416) (xy 438.758584 -11.982196)
			)
		)
	)
	(zone
		(layer "F.Cu")
		(hatch none 0.5)
		(connect_pads
			(clearance 0)
		)
		(min_thickness 0.25)
		(keepout
			(tracks allowed)
			(vias allowed)
			(pads allowed)
			(copperpour allowed)
			(footprints allowed)
		)
		(placement
			(enabled no)
			(sheetname "")
		)
		(fill
			(thermal_gap 0.5)
			(thermal_bridge_width 0.5)
			(island_removal_mode 0)
		)
		(polygon
			(pts
				(xy 41.29151 -284.666436) (xy 41.29151 -284.222698) (xy 43.616626 -284.222698) (xy 43.616626 -284.666436)
			)
		)
	)
	(zone
		(layer "F.Cu")
		(hatch none 0.5)
		(connect_pads
			(clearance 0)
		)
		(min_thickness 0.25)
		(keepout
			(tracks allowed)
			(vias allowed)
			(pads allowed)
			(copperpour allowed)
			(footprints allowed)
		)
		(placement
			(enabled no)
			(sheetname "")
		)
		(fill
			(thermal_gap 0.5)
			(thermal_bridge_width 0.5)
			(island_removal_mode 0)
		)
		(polygon
			(pts
				(xy 64.027812 -211.566506) (xy 64.027812 -211.122768) (xy 66.161412 -211.122768) (xy 66.161412 -211.566506)
			)
		)
	)
	(zone
		(layer "F.Cu")
		(hatch none 0.5)
		(connect_pads
			(clearance 0)
		)
		(min_thickness 0.25)
		(keepout
			(tracks allowed)
			(vias allowed)
			(pads allowed)
			(copperpour allowed)
			(footprints allowed)
		)
		(placement
			(enabled no)
			(sheetname "")
		)
		(fill
			(thermal_gap 0.5)
			(thermal_bridge_width 0.5)
			(island_removal_mode 0)
		)
		(polygon
			(pts
				(xy 44.735242 -220.9165) (xy 44.735242 -220.472762) (xy 47.060358 -220.472762) (xy 47.060358 -220.9165)
			)
		)
	)
	(zone
		(layer "F.Cu")
		(hatch none 0.5)
		(connect_pads
			(clearance 0)
		)
		(min_thickness 0.25)
		(keepout
			(tracks allowed)
			(vias allowed)
			(pads allowed)
			(copperpour allowed)
			(footprints allowed)
		)
		(placement
			(enabled no)
			(sheetname "")
		)
		(fill
			(thermal_gap 0.5)
			(thermal_bridge_width 0.5)
			(island_removal_mode 0)
		)
		(polygon
			(pts
				(xy 332.438502 -410.948886) (xy 332.438502 -406.105868) (xy 334.322928 -406.105868) (xy 334.322928 -410.948886)
			)
		)
	)
	(zone
		(layer "F.Cu")
		(hatch none 0.5)
		(connect_pads
			(clearance 0)
		)
		(min_thickness 0.25)
		(keepout
			(tracks allowed)
			(vias allowed)
			(pads allowed)
			(copperpour allowed)
			(footprints not_allowed)
		)
		(placement
			(enabled no)
			(sheetname "")
		)
		(fill
			(thermal_gap 0.5)
			(thermal_bridge_width 0.5)
			(island_removal_mode 0)
		)
		(polygon
			(pts
				(xy 431.394108 -161.306256) (xy 452.394066 -161.308542) (xy 452.394066 -139.308586) (xy 431.396394 -139.309856)
			)
		)
	)
	(zone
		(layer "F.Cu")
		(hatch none 0.5)
		(connect_pads
			(clearance 0)
		)
		(min_thickness 0.25)
		(keepout
			(tracks allowed)
			(vias allowed)
			(pads allowed)
			(copperpour allowed)
			(footprints allowed)
		)
		(placement
			(enabled no)
			(sheetname "")
		)
		(fill
			(thermal_gap 0.5)
			(thermal_bridge_width 0.5)
			(island_removal_mode 0)
		)
		(polygon
			(pts
				(xy 161.891726 -220.804994) (xy 161.891726 -220.576394) (xy 163.923726 -220.576394) (xy 163.923726 -220.804994)
			)
		)
	)
	(zone
		(layer "F.Cu")
		(hatch none 0.5)
		(connect_pads
			(clearance 0)
		)
		(min_thickness 0.25)
		(keepout
			(tracks allowed)
			(vias allowed)
			(pads allowed)
			(copperpour allowed)
			(footprints allowed)
		)
		(placement
			(enabled no)
			(sheetname "")
		)
		(fill
			(thermal_gap 0.5)
			(thermal_bridge_width 0.5)
			(island_removal_mode 0)
		)
		(polygon
			(pts
				(xy 405.731726 -235.876338) (xy 407.763726 -235.876338) (xy 408.220926 -235.876338) (xy 408.220926 -236.991906)
				(xy 405.230584 -236.991906) (xy 405.230584 -235.876338)
			)
		)
	)
	(zone
		(layer "F.Cu")
		(hatch none 0.5)
		(connect_pads
			(clearance 0)
		)
		(min_thickness 0.25)
		(keepout
			(tracks allowed)
			(vias allowed)
			(pads allowed)
			(copperpour allowed)
			(footprints allowed)
		)
		(placement
			(enabled no)
			(sheetname "")
		)
		(fill
			(thermal_gap 0.5)
			(thermal_bridge_width 0.5)
			(island_removal_mode 0)
		)
		(polygon
			(pts
				(xy 135.4328 -216.055448) (xy 135.71982 -216.055448) (xy 135.7503 -216.024968) (xy 135.7503 -215.397588)
				(xy 135.66394 -215.311228) (xy 135.47598 -215.311228) (xy 135.40232 -215.384888) (xy 135.40232 -216.024968)
			)
		)
	)
	(zone
		(layer "F.Cu")
		(hatch none 0.5)
		(connect_pads
			(clearance 0)
		)
		(min_thickness 0.25)
		(keepout
			(tracks allowed)
			(vias allowed)
			(pads allowed)
			(copperpour allowed)
			(footprints allowed)
		)
		(placement
			(enabled no)
			(sheetname "")
		)
		(fill
			(thermal_gap 0.5)
			(thermal_bridge_width 0.5)
			(island_removal_mode 0)
		)
		(polygon
			(pts
				(xy 304.319178 -278.272748) (xy 306.644294 -278.272748) (xy 306.68214 -278.272748) (xy 306.68214 -279.203912)
				(xy 304.221896 -279.203912) (xy 304.221896 -278.272748)
			)
		)
	)
	(zone
		(layer "F.Cu")
		(hatch none 0.5)
		(connect_pads
			(clearance 0)
		)
		(min_thickness 0.25)
		(keepout
			(tracks allowed)
			(vias allowed)
			(pads allowed)
			(copperpour allowed)
			(footprints allowed)
		)
		(placement
			(enabled no)
			(sheetname "")
		)
		(fill
			(thermal_gap 0.5)
			(thermal_bridge_width 0.5)
			(island_removal_mode 0)
		)
		(polygon
			(pts
				(xy 165.335458 -220.804994) (xy 165.335458 -220.576394) (xy 167.367458 -220.576394) (xy 167.367458 -220.804994)
			)
		)
	)
	(zone
		(layer "F.Cu")
		(hatch none 0.5)
		(connect_pads
			(clearance 0)
		)
		(min_thickness 0.25)
		(keepout
			(tracks allowed)
			(vias allowed)
			(pads allowed)
			(copperpour allowed)
			(footprints allowed)
		)
		(placement
			(enabled no)
			(sheetname "")
		)
		(fill
			(thermal_gap 0.5)
			(thermal_bridge_width 0.5)
			(island_removal_mode 0)
		)
		(polygon
			(pts
				(xy 311.91708 -209.866484) (xy 311.91708 -209.422746) (xy 314.15228 -209.422746) (xy 314.15228 -209.866484)
			)
		)
	)
	(zone
		(layer "F.Cu")
		(hatch none 0.5)
		(connect_pads
			(clearance 0)
		)
		(min_thickness 0.25)
		(keepout
			(tracks allowed)
			(vias allowed)
			(pads allowed)
			(copperpour allowed)
			(footprints allowed)
		)
		(placement
			(enabled no)
			(sheetname "")
		)
		(fill
			(thermal_gap 0.5)
			(thermal_bridge_width 0.5)
			(island_removal_mode 0)
		)
		(polygon
			(pts
				(xy 26.20391 -300.816518) (xy 26.20391 -300.37278) (xy 28.529026 -300.37278) (xy 28.529026 -300.816518)
			)
		)
	)
	(zone
		(layer "F.Cu")
		(hatch none 0.5)
		(connect_pads
			(clearance 0)
		)
		(min_thickness 0.25)
		(keepout
			(tracks not_allowed)
			(vias allowed)
			(pads allowed)
			(copperpour not_allowed)
			(footprints allowed)
		)
		(placement
			(enabled no)
			(sheetname "")
		)
		(fill
			(thermal_gap 0.5)
			(thermal_bridge_width 0.5)
			(island_removal_mode 0)
		)
		(polygon
			(pts
				(xy 413.009588 -164.68598) (xy 413.53232 -164.68598) (xy 413.758888 -164.459412) (xy 413.758888 -159.896048)
				(xy 413.548576 -159.685736) (xy 413.009588 -159.685736) (xy 413.009588 -159.976058) (xy 413.465264 -159.976058)
				(xy 413.465264 -164.395658) (xy 413.009588 -164.395658)
			)
		)
	)
	(zone
		(layer "F.Cu")
		(hatch none 0.5)
		(connect_pads
			(clearance 0)
		)
		(min_thickness 0.25)
		(keepout
			(tracks not_allowed)
			(vias allowed)
			(pads allowed)
			(copperpour not_allowed)
			(footprints allowed)
		)
		(placement
			(enabled no)
			(sheetname "")
		)
		(fill
			(thermal_gap 0.5)
			(thermal_bridge_width 0.5)
			(island_removal_mode 0)
		)
		(polygon
			(pts
				(arc
					(start 62.782958 -50.249836)
					(mid 59.583066 -47.049944)
					(end 62.782958 -43.850052)
				)
				(arc
					(start 64.382904 -43.850052)
					(mid 67.582796 -47.049944)
					(end 64.382904 -50.249836)
				)
			)
		)
	)
	(zone
		(layer "F.Cu")
		(hatch none 0.5)
		(connect_pads
			(clearance 0)
		)
		(min_thickness 0.25)
		(keepout
			(tracks allowed)
			(vias allowed)
			(pads allowed)
			(copperpour allowed)
			(footprints allowed)
		)
		(placement
			(enabled no)
			(sheetname "")
		)
		(fill
			(thermal_gap 0.5)
			(thermal_bridge_width 0.5)
			(island_removal_mode 0)
		)
		(polygon
			(pts
				(xy 289.231578 -224.316544) (xy 289.231578 -223.872806) (xy 291.556694 -223.872806) (xy 291.556694 -224.316544)
			)
		)
	)
	(zone
		(layer "F.Cu")
		(hatch none 0.5)
		(connect_pads
			(clearance 0)
		)
		(min_thickness 0.25)
		(keepout
			(tracks allowed)
			(vias allowed)
			(pads allowed)
			(copperpour allowed)
			(footprints allowed)
		)
		(placement
			(enabled no)
			(sheetname "")
		)
		(fill
			(thermal_gap 0.5)
			(thermal_bridge_width 0.5)
			(island_removal_mode 0)
		)
		(polygon
			(pts
				(xy 59.822842 -199.666606) (xy 59.822842 -199.222868) (xy 62.147958 -199.222868) (xy 62.147958 -199.666606)
			)
		)
	)
	(zone
		(layer "F.Cu")
		(hatch none 0.5)
		(connect_pads
			(clearance 0)
		)
		(min_thickness 0.25)
		(keepout
			(tracks allowed)
			(vias allowed)
			(pads allowed)
			(copperpour allowed)
			(footprints allowed)
		)
		(placement
			(enabled no)
			(sheetname "")
		)
		(fill
			(thermal_gap 0.5)
			(thermal_bridge_width 0.5)
			(island_removal_mode 0)
		)
		(polygon
			(pts
				(xy 458.538326 -211.455) (xy 458.538326 -211.2264) (xy 460.570326 -211.2264) (xy 460.570326 -211.455)
			)
		)
	)
	(zone
		(layer "F.Cu")
		(hatch none 0.5)
		(connect_pads
			(clearance 0)
		)
		(min_thickness 0.25)
		(keepout
			(tracks allowed)
			(vias allowed)
			(pads allowed)
			(copperpour allowed)
			(footprints allowed)
		)
		(placement
			(enabled no)
			(sheetname "")
		)
		(fill
			(thermal_gap 0.5)
			(thermal_bridge_width 0.5)
			(island_removal_mode 0)
		)
		(polygon
			(pts
				(xy 157.791658 -246.304816) (xy 157.791658 -246.076216) (xy 159.823658 -246.076216) (xy 159.823658 -246.304816)
			)
		)
	)
	(zone
		(layer "F.Cu")
		(hatch none 0.5)
		(connect_pads
			(clearance 0)
		)
		(min_thickness 0.25)
		(keepout
			(tracks allowed)
			(vias allowed)
			(pads allowed)
			(copperpour allowed)
			(footprints allowed)
		)
		(placement
			(enabled no)
			(sheetname "")
		)
		(fill
			(thermal_gap 0.5)
			(thermal_bridge_width 0.5)
			(island_removal_mode 0)
		)
		(polygon
			(pts
				(xy 258.905756 -319.243456) (xy 258.905756 -316.881256) (xy 261.521956 -316.881256) (xy 261.521956 -319.243456)
			)
		)
	)
	(zone
		(layer "F.Cu")
		(hatch none 0.5)
		(connect_pads
			(clearance 0)
		)
		(min_thickness 0.25)
		(keepout
			(tracks allowed)
			(vias allowed)
			(pads allowed)
			(copperpour allowed)
			(footprints allowed)
		)
		(placement
			(enabled no)
			(sheetname "")
		)
		(fill
			(thermal_gap 0.5)
			(thermal_bridge_width 0.5)
			(island_removal_mode 0)
		)
		(polygon
			(pts
				(xy 310.088026 -235.36656) (xy 307.76291 -235.36656) (xy 307.62448 -235.36656) (xy 307.62448 -234.447334)
				(xy 310.153304 -234.447334) (xy 310.153304 -235.36656)
			)
		)
	)
	(zone
		(layer "F.Cu")
		(hatch none 0.5)
		(connect_pads
			(clearance 0)
		)
		(min_thickness 0.25)
		(keepout
			(tracks allowed)
			(vias allowed)
			(pads allowed)
			(copperpour allowed)
			(footprints allowed)
		)
		(placement
			(enabled no)
			(sheetname "")
		)
		(fill
			(thermal_gap 0.5)
			(thermal_bridge_width 0.5)
			(island_removal_mode 0)
		)
		(polygon
			(pts
				(xy 285.13786 -367.876328) (xy 285.13786 -365.349028) (xy 291.10686 -365.349028) (xy 291.10686 -367.876328)
			)
		)
	)
	(zone
		(layer "F.Cu")
		(hatch none 0.5)
		(connect_pads
			(clearance 0)
		)
		(min_thickness 0.25)
		(keepout
			(tracks allowed)
			(vias allowed)
			(pads allowed)
			(copperpour allowed)
			(footprints allowed)
		)
		(placement
			(enabled no)
			(sheetname "")
		)
		(fill
			(thermal_gap 0.5)
			(thermal_bridge_width 0.5)
			(island_removal_mode 0)
		)
		(polygon
			(pts
				(xy 165.335458 -302.405034) (xy 165.335458 -302.176434) (xy 167.367458 -302.176434) (xy 167.367458 -302.405034)
			)
		)
	)
	(zone
		(layer "F.Cu")
		(hatch none 0.5)
		(connect_pads
			(clearance 0)
		)
		(min_thickness 0.25)
		(keepout
			(tracks not_allowed)
			(vias allowed)
			(pads allowed)
			(copperpour not_allowed)
			(footprints allowed)
		)
		(placement
			(enabled no)
			(sheetname "")
		)
		(fill
			(thermal_gap 0.5)
			(thermal_bridge_width 0.5)
			(island_removal_mode 0)
		)
		(polygon
			(pts
				(arc
					(start 68.13296 -47.049944)
					(mid 70.382892 -44.800012)
					(end 72.632824 -47.049944)
				)
				(arc
					(start 72.632824 -47.049944)
					(mid 70.382892 -49.299876)
					(end 68.13296 -47.049944)
				)
			)
		)
	)
	(zone
		(layer "F.Cu")
		(hatch none 0.5)
		(connect_pads
			(clearance 0)
		)
		(min_thickness 0.25)
		(keepout
			(tracks allowed)
			(vias allowed)
			(pads allowed)
			(copperpour allowed)
			(footprints allowed)
		)
		(placement
			(enabled no)
			(sheetname "")
		)
		(fill
			(thermal_gap 0.5)
			(thermal_bridge_width 0.5)
			(island_removal_mode 0)
		)
		(polygon
			(pts
				(xy 261.92988 -67.351148) (xy 261.92988 -66.731388) (xy 263.98728 -66.731388) (xy 263.98728 -67.351148)
			)
		)
	)
	(zone
		(layer "F.Cu")
		(hatch none 0.5)
		(connect_pads
			(clearance 0)
		)
		(min_thickness 0.25)
		(keepout
			(tracks allowed)
			(vias allowed)
			(pads allowed)
			(copperpour allowed)
			(footprints allowed)
		)
		(placement
			(enabled no)
			(sheetname "")
		)
		(fill
			(thermal_gap 0.5)
			(thermal_bridge_width 0.5)
			(island_removal_mode 0)
		)
		(polygon
			(pts
				(xy 413.307022 -267.554964) (xy 413.307022 -267.326364) (xy 415.307526 -267.326364) (xy 415.307526 -267.554964)
			)
		)
	)
	(zone
		(layer "F.Cu")
		(hatch none 0.5)
		(connect_pads
			(clearance 0)
		)
		(min_thickness 0.25)
		(keepout
			(tracks allowed)
			(vias allowed)
			(pads allowed)
			(copperpour allowed)
			(footprints allowed)
		)
		(placement
			(enabled no)
			(sheetname "")
		)
		(fill
			(thermal_gap 0.5)
			(thermal_bridge_width 0.5)
			(island_removal_mode 0)
		)
		(polygon
			(pts
				(xy 277.58771 -281.266646) (xy 277.58771 -280.822908) (xy 279.912826 -280.822908) (xy 279.912826 -281.266646)
			)
		)
	)
	(zone
		(layer "F.Cu")
		(hatch none 0.5)
		(connect_pads
			(clearance 0)
		)
		(min_thickness 0.25)
		(keepout
			(tracks allowed)
			(vias allowed)
			(pads allowed)
			(copperpour allowed)
			(footprints allowed)
		)
		(placement
			(enabled no)
			(sheetname "")
		)
		(fill
			(thermal_gap 0.5)
			(thermal_bridge_width 0.5)
			(island_removal_mode 0)
		)
		(polygon
			(pts
				(xy 180.423058 -287.954974) (xy 180.423058 -287.726374) (xy 182.455058 -287.726374) (xy 182.455058 -287.954974)
			)
		)
	)
	(zone
		(layer "F.Cu")
		(hatch none 0.5)
		(connect_pads
			(clearance 0)
		)
		(min_thickness 0.25)
		(keepout
			(tracks allowed)
			(vias allowed)
			(pads allowed)
			(copperpour allowed)
			(footprints not_allowed)
		)
		(placement
			(enabled no)
			(sheetname "")
		)
		(fill
			(thermal_gap 0.5)
			(thermal_bridge_width 0.5)
			(island_removal_mode 0)
		)
		(polygon
			(pts
				(xy 195.532502 -330.091796) (xy 201.632312 -330.091796) (xy 201.632312 -186.09183) (xy 195.532502 -186.09183)
			)
		)
	)
	(zone
		(layer "F.Cu")
		(hatch none 0.5)
		(connect_pads
			(clearance 0)
		)
		(min_thickness 0.25)
		(keepout
			(tracks allowed)
			(vias allowed)
			(pads allowed)
			(copperpour allowed)
			(footprints allowed)
		)
		(placement
			(enabled no)
			(sheetname "")
		)
		(fill
			(thermal_gap 0.5)
			(thermal_bridge_width 0.5)
			(island_removal_mode 0)
		)
		(polygon
			(pts
				(xy 428.363126 -224.204784) (xy 428.363126 -223.976184) (xy 430.395126 -223.976184) (xy 430.395126 -224.204784)
			)
		)
	)
	(zone
		(layer "F.Cu")
		(hatch none 0.5)
		(connect_pads
			(clearance 0)
		)
		(min_thickness 0.25)
		(keepout
			(tracks not_allowed)
			(vias allowed)
			(pads allowed)
			(copperpour not_allowed)
			(footprints allowed)
		)
		(placement
			(enabled no)
			(sheetname "")
		)
		(fill
			(thermal_gap 0.5)
			(thermal_bridge_width 0.5)
			(island_removal_mode 0)
		)
		(polygon
			(pts
				(arc
					(start 184.62498 -66.06794)
					(mid 178.86299 -60.30595)
					(end 173.101 -66.06794)
				)
				(arc
					(start 173.101 -74.767948)
					(mid 178.86299 -80.529938)
					(end 184.62498 -74.767948)
				)
			)
		)
	)
	(zone
		(layer "F.Cu")
		(hatch none 0.5)
		(connect_pads
			(clearance 0)
		)
		(min_thickness 0.25)
		(keepout
			(tracks allowed)
			(vias allowed)
			(pads allowed)
			(copperpour allowed)
			(footprints allowed)
		)
		(placement
			(enabled no)
			(sheetname "")
		)
		(fill
			(thermal_gap 0.5)
			(thermal_bridge_width 0.5)
			(island_removal_mode 0)
		)
		(polygon
			(pts
				(xy 443.450726 -299.00499) (xy 443.450726 -298.77639) (xy 445.482726 -298.77639) (xy 445.482726 -299.00499)
			)
		)
	)
	(zone
		(layer "F.Cu")
		(hatch none 0.5)
		(connect_pads
			(clearance 0)
		)
		(min_thickness 0.25)
		(keepout
			(tracks allowed)
			(vias allowed)
			(pads allowed)
			(copperpour allowed)
			(footprints allowed)
		)
		(placement
			(enabled no)
			(sheetname "")
		)
		(fill
			(thermal_gap 0.5)
			(thermal_bridge_width 0.5)
			(island_removal_mode 0)
		)
		(polygon
			(pts
				(xy 289.231578 -233.666538) (xy 289.231578 -233.2228) (xy 291.556694 -233.2228) (xy 291.556694 -233.666538)
			)
		)
	)
	(zone
		(layer "F.Cu")
		(hatch none 0.5)
		(connect_pads
			(clearance 0)
		)
		(min_thickness 0.25)
		(keepout
			(tracks allowed)
			(vias allowed)
			(pads allowed)
			(copperpour allowed)
			(footprints allowed)
		)
		(placement
			(enabled no)
			(sheetname "")
		)
		(fill
			(thermal_gap 0.5)
			(thermal_bridge_width 0.5)
			(island_removal_mode 0)
		)
		(polygon
			(pts
				(xy 332.860904 -260.913372) (xy 333.06385 -260.710426) (xy 333.06385 -260.6675) (xy 332.620366 -260.223762)
				(xy 332.498192 -260.223762) (xy 332.365096 -260.356604) (xy 332.365096 -260.460744) (xy 332.817724 -260.913372)
			)
		)
	)
	(zone
		(layer "F.Cu")
		(hatch none 0.5)
		(connect_pads
			(clearance 0)
		)
		(min_thickness 0.25)
		(keepout
			(tracks allowed)
			(vias allowed)
			(pads allowed)
			(copperpour allowed)
			(footprints allowed)
		)
		(placement
			(enabled no)
			(sheetname "")
		)
		(fill
			(thermal_gap 0.5)
			(thermal_bridge_width 0.5)
			(island_removal_mode 0)
		)
		(polygon
			(pts
				(xy 207.154526 -295.376346) (xy 209.186526 -295.376346) (xy 209.186526 -295.604946) (xy 207.154526 -295.604946)
				(xy 207.018382 -295.604946) (xy 206.971392 -295.604946) (xy 206.971392 -295.376346) (xy 207.018382 -295.376346)
			)
		)
	)
	(zone
		(layer "F.Cu")
		(hatch none 0.5)
		(connect_pads
			(clearance 0)
		)
		(min_thickness 0.25)
		(keepout
			(tracks allowed)
			(vias allowed)
			(pads allowed)
			(copperpour allowed)
			(footprints allowed)
		)
		(placement
			(enabled no)
			(sheetname "")
		)
		(fill
			(thermal_gap 0.5)
			(thermal_bridge_width 0.5)
			(island_removal_mode 0)
		)
		(polygon
			(pts
				(xy 72.028812 -404.802594) (xy 72.028812 -399.959576) (xy 73.913238 -399.959576) (xy 73.913238 -404.802594)
			)
		)
	)
	(zone
		(layer "F.Cu")
		(hatch none 0.5)
		(connect_pads
			(clearance 0)
		)
		(min_thickness 0.25)
		(keepout
			(tracks allowed)
			(vias allowed)
			(pads allowed)
			(copperpour allowed)
			(footprints allowed)
		)
		(placement
			(enabled no)
			(sheetname "")
		)
		(fill
			(thermal_gap 0.5)
			(thermal_bridge_width 0.5)
			(island_removal_mode 0)
		)
		(polygon
			(pts
				(xy 428.363126 -233.555032) (xy 428.363126 -233.326432) (xy 430.395126 -233.326432) (xy 430.395126 -233.555032)
			)
		)
	)
	(zone
		(layer "F.Cu")
		(hatch none 0.5)
		(connect_pads
			(clearance 0)
		)
		(min_thickness 0.25)
		(keepout
			(tracks allowed)
			(vias allowed)
			(pads allowed)
			(copperpour allowed)
			(footprints allowed)
		)
		(placement
			(enabled no)
			(sheetname "")
		)
		(fill
			(thermal_gap 0.5)
			(thermal_bridge_width 0.5)
			(island_removal_mode 0)
		)
		(polygon
			(pts
				(xy 292.67531 -269.366492) (xy 292.67531 -268.922754) (xy 295.000426 -268.922754) (xy 295.000426 -269.366492)
			)
		)
	)
	(zone
		(layer "F.Cu")
		(hatch none 0.5)
		(connect_pads
			(clearance 0)
		)
		(min_thickness 0.25)
		(keepout
			(tracks allowed)
			(vias allowed)
			(pads allowed)
			(copperpour allowed)
			(footprints not_allowed)
		)
		(placement
			(enabled no)
			(sheetname "")
		)
		(fill
			(thermal_gap 0.5)
			(thermal_bridge_width 0.5)
			(island_removal_mode 0)
		)
		(polygon
			(pts
				(xy 416.30219 -79.76362) (xy 303.502314 -79.76362) (xy 303.502314 -82.763614) (xy 416.30219 -82.763614)
			)
		)
	)
	(zone
		(layer "F.Cu")
		(hatch none 0.5)
		(connect_pads
			(clearance 0)
		)
		(min_thickness 0.25)
		(keepout
			(tracks allowed)
			(vias allowed)
			(pads allowed)
			(copperpour allowed)
			(footprints allowed)
		)
		(placement
			(enabled no)
			(sheetname "")
		)
		(fill
			(thermal_gap 0.5)
			(thermal_bridge_width 0.5)
			(island_removal_mode 0)
		)
		(polygon
			(pts
				(xy 407.763726 -233.555032) (xy 405.731726 -233.555032) (xy 405.540464 -233.555032) (xy 405.540464 -232.817416)
				(xy 407.971498 -232.817416) (xy 407.971498 -233.555032)
			)
		)
	)
	(zone
		(layer "F.Cu")
		(hatch none 0.5)
		(connect_pads
			(clearance 0)
		)
		(min_thickness 0.25)
		(keepout
			(tracks allowed)
			(vias allowed)
			(pads allowed)
			(copperpour allowed)
			(footprints not_allowed)
		)
		(placement
			(enabled no)
			(sheetname "")
		)
		(fill
			(thermal_gap 0.5)
			(thermal_bridge_width 0.5)
			(island_removal_mode 0)
		)
		(polygon
			(pts
				(xy 72.497188 -347.521784) (xy 72.497188 -328.521822) (xy 67.04711 -328.521822) (xy 67.04711 -331.091794)
				(xy 6.140704 -331.091794) (xy 6.140704 -328.521822) (xy 2.999994 -328.521822)
				(arc
					(start 2.999994 -344.518234)
					(mid 11.877474 -339.84913)
					(end 18.338038 -347.521784)
				)
			)
		)
	)
	(zone
		(layer "F.Cu")
		(hatch none 0.5)
		(connect_pads
			(clearance 0)
		)
		(min_thickness 0.25)
		(keepout
			(tracks allowed)
			(vias allowed)
			(pads allowed)
			(copperpour allowed)
			(footprints allowed)
		)
		(placement
			(enabled no)
			(sheetname "")
		)
		(fill
			(thermal_gap 0.5)
			(thermal_bridge_width 0.5)
			(island_removal_mode 0)
		)
		(polygon
			(pts
				(xy 424.919394 -231.62641) (xy 426.951394 -231.62641) (xy 426.951394 -231.85501) (xy 424.919394 -231.85501)
				(xy 424.78325 -231.85501) (xy 424.73626 -231.85501) (xy 424.73626 -231.62641) (xy 424.78325 -231.62641)
			)
		)
	)
	(zone
		(layer "F.Cu")
		(hatch none 0.5)
		(connect_pads
			(clearance 0)
		)
		(min_thickness 0.25)
		(keepout
			(tracks not_allowed)
			(vias allowed)
			(pads allowed)
			(copperpour not_allowed)
			(footprints allowed)
		)
		(placement
			(enabled no)
			(sheetname "")
		)
		(fill
			(thermal_gap 0.5)
			(thermal_bridge_width 0.5)
			(island_removal_mode 0)
		)
		(polygon
			(pts
				(xy 25.82672 -162.947604) (xy 29.51226 -162.947604) (xy 29.51226 -162.931348) (xy 29.694886 -162.931348)
				(xy 29.694886 -162.795204) (xy 25.630886 -162.795204) (xy 25.630886 -162.908488) (xy 25.82672 -162.908488)
			)
		)
	)
	(zone
		(layer "F.Cu")
		(hatch none 0.5)
		(connect_pads
			(clearance 0)
		)
		(min_thickness 0.25)
		(keepout
			(tracks allowed)
			(vias allowed)
			(pads allowed)
			(copperpour allowed)
			(footprints allowed)
		)
		(placement
			(enabled no)
			(sheetname "")
		)
		(fill
			(thermal_gap 0.5)
			(thermal_bridge_width 0.5)
			(island_removal_mode 0)
		)
		(polygon
			(pts
				(xy 41.29151 -250.666504) (xy 41.29151 -250.222766) (xy 43.616626 -250.222766) (xy 43.616626 -250.666504)
			)
		)
	)
	(zone
		(layer "F.Cu")
		(hatch none 0.5)
		(connect_pads
			(clearance 0)
		)
		(min_thickness 0.25)
		(keepout
			(tracks allowed)
			(vias allowed)
			(pads allowed)
			(copperpour allowed)
			(footprints allowed)
		)
		(placement
			(enabled no)
			(sheetname "")
		)
		(fill
			(thermal_gap 0.5)
			(thermal_bridge_width 0.5)
			(island_removal_mode 0)
		)
		(polygon
			(pts
				(xy 259.056378 -267.66647) (xy 259.056378 -267.222732) (xy 261.381494 -267.222732) (xy 261.381494 -267.66647)
			)
		)
	)
	(zone
		(layer "F.Cu")
		(hatch none 0.5)
		(connect_pads
			(clearance 0)
		)
		(min_thickness 0.25)
		(keepout
			(tracks allowed)
			(vias allowed)
			(pads allowed)
			(copperpour allowed)
			(footprints allowed)
		)
		(placement
			(enabled no)
			(sheetname "")
		)
		(fill
			(thermal_gap 0.5)
			(thermal_bridge_width 0.5)
			(island_removal_mode 0)
		)
		(polygon
			(pts
				(xy 443.450726 -301.554896) (xy 443.450726 -301.326296) (xy 445.482726 -301.326296) (xy 445.482726 -301.554896)
			)
		)
	)
	(zone
		(layer "F.Cu")
		(hatch none 0.5)
		(connect_pads
			(clearance 0)
		)
		(min_thickness 0.25)
		(keepout
			(tracks allowed)
			(vias allowed)
			(pads allowed)
			(copperpour allowed)
			(footprints allowed)
		)
		(placement
			(enabled no)
			(sheetname "")
		)
		(fill
			(thermal_gap 0.5)
			(thermal_bridge_width 0.5)
			(island_removal_mode 0)
		)
		(polygon
			(pts
				(xy 108.67136 -215.268048) (xy 108.95838 -215.268048) (xy 108.98886 -215.237568) (xy 108.98886 -214.610188)
				(xy 108.9025 -214.523828) (xy 108.71454 -214.523828) (xy 108.64088 -214.597488) (xy 108.64088 -215.237568)
			)
		)
	)
	(zone
		(layer "F.Cu")
		(hatch none 0.5)
		(connect_pads
			(clearance 0)
		)
		(min_thickness 0.25)
		(keepout
			(tracks allowed)
			(vias allowed)
			(pads allowed)
			(copperpour allowed)
			(footprints allowed)
		)
		(placement
			(enabled no)
			(sheetname "")
		)
		(fill
			(thermal_gap 0.5)
			(thermal_bridge_width 0.5)
			(island_removal_mode 0)
		)
		(polygon
			(pts
				(xy 343.345262 -404.802594) (xy 343.345262 -399.959576) (xy 345.229688 -399.959576) (xy 345.229688 -404.802594)
			)
		)
	)
	(zone
		(layer "F.Cu")
		(hatch none 0.5)
		(connect_pads
			(clearance 0)
		)
		(min_thickness 0.25)
		(keepout
			(tracks allowed)
			(vias allowed)
			(pads allowed)
			(copperpour allowed)
			(footprints allowed)
		)
		(placement
			(enabled no)
			(sheetname "")
		)
		(fill
			(thermal_gap 0.5)
			(thermal_bridge_width 0.5)
			(island_removal_mode 0)
		)
		(polygon
			(pts
				(xy 26.20391 -216.666572) (xy 26.20391 -216.222834) (xy 28.529026 -216.222834) (xy 28.529026 -216.666572)
			)
		)
	)
	(zone
		(layer "F.Cu")
		(hatch none 0.5)
		(connect_pads
			(clearance 0)
		)
		(min_thickness 0.25)
		(keepout
			(tracks allowed)
			(vias allowed)
			(pads allowed)
			(copperpour allowed)
			(footprints allowed)
		)
		(placement
			(enabled no)
			(sheetname "")
		)
		(fill
			(thermal_gap 0.5)
			(thermal_bridge_width 0.5)
			(island_removal_mode 0)
		)
		(polygon
			(pts
				(xy 450.770498 -268.51737) (xy 453.26554 -268.51737) (xy 453.26554 -269.254986) (xy 453.26554 -269.425674)
				(xy 450.637402 -269.425674) (xy 450.637402 -268.51737)
			)
		)
	)
	(zone
		(layer "F.Cu")
		(hatch none 0.5)
		(connect_pads
			(clearance 0)
		)
		(min_thickness 0.25)
		(keepout
			(tracks not_allowed)
			(vias allowed)
			(pads allowed)
			(copperpour not_allowed)
			(footprints allowed)
		)
		(placement
			(enabled no)
			(sheetname "")
		)
		(fill
			(thermal_gap 0.5)
			(thermal_bridge_width 0.5)
			(island_removal_mode 0)
		)
		(polygon
			(pts
				(xy 327.401428 -342.903048) (xy 327.696322 -342.903048) (xy 327.696322 -342.227662) (xy 326.146922 -342.227662)
				(xy 326.146922 -342.684354) (xy 326.842628 -342.684354) (xy 326.842628 -342.523826) (xy 327.401428 -342.523826)
			)
		)
	)
	(zone
		(layer "F.Cu")
		(hatch none 0.5)
		(connect_pads
			(clearance 0)
		)
		(min_thickness 0.25)
		(keepout
			(tracks allowed)
			(vias allowed)
			(pads allowed)
			(copperpour allowed)
			(footprints allowed)
		)
		(placement
			(enabled no)
			(sheetname "")
		)
		(fill
			(thermal_gap 0.5)
			(thermal_bridge_width 0.5)
			(island_removal_mode 0)
		)
		(polygon
			(pts
				(xy 335.47812 -217.663268) (xy 335.76514 -217.663268) (xy 335.79562 -217.632788) (xy 335.79562 -217.005408)
				(xy 335.70926 -216.919048) (xy 335.5213 -216.919048) (xy 335.44764 -216.992708) (xy 335.44764 -217.632788)
			)
		)
	)
	(zone
		(layer "F.Cu")
		(hatch none 0.5)
		(connect_pads
			(clearance 0)
		)
		(min_thickness 0.25)
		(keepout
			(tracks allowed)
			(vias allowed)
			(pads allowed)
			(copperpour allowed)
			(footprints allowed)
		)
		(placement
			(enabled no)
			(sheetname "")
		)
		(fill
			(thermal_gap 0.5)
			(thermal_bridge_width 0.5)
			(island_removal_mode 0)
		)
		(polygon
			(pts
				(xy 424.919394 -210.376262) (xy 426.951394 -210.376262) (xy 426.951394 -210.604862) (xy 424.919394 -210.604862)
				(xy 424.788076 -210.604862) (xy 424.762168 -210.604862) (xy 424.762168 -210.376262) (xy 424.788076 -210.376262)
			)
		)
	)
	(zone
		(layer "F.Cu")
		(hatch none 0.5)
		(connect_pads
			(clearance 0)
		)
		(min_thickness 0.25)
		(keepout
			(tracks allowed)
			(vias allowed)
			(pads allowed)
			(copperpour allowed)
			(footprints allowed)
		)
		(placement
			(enabled no)
			(sheetname "")
		)
		(fill
			(thermal_gap 0.5)
			(thermal_bridge_width 0.5)
			(island_removal_mode 0)
		)
		(polygon
			(pts
				(xy 29.647642 -264.266426) (xy 29.647642 -263.822688) (xy 31.972758 -263.822688) (xy 31.972758 -264.266426)
			)
		)
	)
	(zone
		(layer "F.Cu")
		(hatch none 0.5)
		(connect_pads
			(clearance 0)
		)
		(min_thickness 0.25)
		(keepout
			(tracks allowed)
			(vias allowed)
			(pads allowed)
			(copperpour allowed)
			(footprints allowed)
		)
		(placement
			(enabled no)
			(sheetname "")
		)
		(fill
			(thermal_gap 0.5)
			(thermal_bridge_width 0.5)
			(island_removal_mode 0)
		)
		(polygon
			(pts
				(xy 424.919394 -303.25695) (xy 426.951394 -303.25695) (xy 426.951394 -303.02835) (xy 424.919394 -303.02835)
				(xy 424.788076 -303.02835) (xy 424.762168 -303.02835) (xy 424.762168 -303.25695) (xy 424.788076 -303.25695)
			)
		)
	)
	(zone
		(layer "F.Cu")
		(hatch none 0.5)
		(connect_pads
			(clearance 0)
		)
		(min_thickness 0.25)
		(keepout
			(tracks allowed)
			(vias allowed)
			(pads allowed)
			(copperpour allowed)
			(footprints allowed)
		)
		(placement
			(enabled no)
			(sheetname "")
		)
		(fill
			(thermal_gap 0.5)
			(thermal_bridge_width 0.5)
			(island_removal_mode 0)
		)
		(polygon
			(pts
				(xy 405.737822 -240.126266) (xy 407.769822 -240.126266) (xy 407.910284 -240.126266) (xy 407.910284 -240.838736)
				(xy 405.522176 -240.838736) (xy 405.522176 -240.126266)
			)
		)
	)
	(zone
		(layer "F.Cu")
		(hatch none 0.5)
		(connect_pads
			(clearance 0)
		)
		(min_thickness 0.25)
		(keepout
			(tracks allowed)
			(vias allowed)
			(pads allowed)
			(copperpour allowed)
			(footprints allowed)
		)
		(placement
			(enabled no)
			(sheetname "")
		)
		(fill
			(thermal_gap 0.5)
			(thermal_bridge_width 0.5)
			(island_removal_mode 0)
		)
		(polygon
			(pts
				(xy 289.231578 -228.566472) (xy 289.231578 -228.122734) (xy 291.556694 -228.122734) (xy 291.556694 -228.566472)
			)
		)
	)
	(zone
		(layer "F.Cu")
		(hatch none 0.5)
		(connect_pads
			(clearance 0)
		)
		(min_thickness 0.25)
		(keepout
			(tracks allowed)
			(vias allowed)
			(pads allowed)
			(copperpour allowed)
			(footprints allowed)
		)
		(placement
			(enabled no)
			(sheetname "")
		)
		(fill
			(thermal_gap 0.5)
			(thermal_bridge_width 0.5)
			(island_removal_mode 0)
		)
		(polygon
			(pts
				(xy 424.919394 -219.726256) (xy 426.951394 -219.726256) (xy 426.951394 -219.954856) (xy 424.919394 -219.954856)
				(xy 424.788076 -219.954856) (xy 424.762168 -219.954856) (xy 424.762168 -219.726256) (xy 424.788076 -219.726256)
			)
		)
	)
	(zone
		(layer "F.Cu")
		(hatch none 0.5)
		(connect_pads
			(clearance 0)
		)
		(min_thickness 0.25)
		(keepout
			(tracks not_allowed)
			(vias allowed)
			(pads allowed)
			(copperpour not_allowed)
			(footprints allowed)
		)
		(placement
			(enabled no)
			(sheetname "")
		)
		(fill
			(thermal_gap 0.5)
			(thermal_bridge_width 0.5)
			(island_removal_mode 0)
		)
		(polygon
			(pts
				(xy 417.716462 -163.987988) (xy 416.652202 -163.987988) (xy 416.603942 -164.036248) (xy 416.603942 -164.230304)
				(xy 417.716462 -164.230304)
			)
		)
	)
	(zone
		(layer "F.Cu")
		(hatch none 0.5)
		(connect_pads
			(clearance 0)
		)
		(min_thickness 0.25)
		(keepout
			(tracks allowed)
			(vias allowed)
			(pads allowed)
			(copperpour allowed)
			(footprints allowed)
		)
		(placement
			(enabled no)
			(sheetname "")
		)
		(fill
			(thermal_gap 0.5)
			(thermal_bridge_width 0.5)
			(island_removal_mode 0)
		)
		(polygon
			(pts
				(xy 292.67531 -205.616556) (xy 292.67531 -205.172818) (xy 295.000426 -205.172818) (xy 295.000426 -205.616556)
			)
		)
	)
	(zone
		(layer "F.Cu")
		(hatch none 0.5)
		(connect_pads
			(clearance 0)
		)
		(min_thickness 0.25)
		(keepout
			(tracks allowed)
			(vias allowed)
			(pads allowed)
			(copperpour allowed)
			(footprints allowed)
		)
		(placement
			(enabled no)
			(sheetname "")
		)
		(fill
			(thermal_gap 0.5)
			(thermal_bridge_width 0.5)
			(island_removal_mode 0)
		)
		(polygon
			(pts
				(xy 289.231578 -245.566438) (xy 289.231578 -245.1227) (xy 291.556694 -245.1227) (xy 291.556694 -245.566438)
			)
		)
	)
	(zone
		(layer "F.Cu")
		(hatch none 0.5)
		(connect_pads
			(clearance 0)
		)
		(min_thickness 0.25)
		(keepout
			(tracks allowed)
			(vias allowed)
			(pads allowed)
			(copperpour allowed)
			(footprints allowed)
		)
		(placement
			(enabled no)
			(sheetname "")
		)
		(fill
			(thermal_gap 0.5)
			(thermal_bridge_width 0.5)
			(island_removal_mode 0)
		)
		(polygon
			(pts
				(xy 121.35866 -117.668548) (xy 121.35866 -115.169188) (xy 126.57582 -115.169188) (xy 126.57582 -117.668548)
			)
		)
	)
	(zone
		(layer "F.Cu")
		(hatch none 0.5)
		(connect_pads
			(clearance 0)
		)
		(min_thickness 0.25)
		(keepout
			(tracks allowed)
			(vias allowed)
			(pads allowed)
			(copperpour allowed)
			(footprints allowed)
		)
		(placement
			(enabled no)
			(sheetname "")
		)
		(fill
			(thermal_gap 0.5)
			(thermal_bridge_width 0.5)
			(island_removal_mode 0)
		)
		(polygon
			(pts
				(xy 262.50011 -311.01665) (xy 262.50011 -310.572912) (xy 264.825226 -310.572912) (xy 264.825226 -311.01665)
			)
		)
	)
	(zone
		(layer "F.Cu")
		(hatch none 0.5)
		(connect_pads
			(clearance 0)
		)
		(min_thickness 0.25)
		(keepout
			(tracks allowed)
			(vias allowed)
			(pads allowed)
			(copperpour allowed)
			(footprints allowed)
		)
		(placement
			(enabled no)
			(sheetname "")
		)
		(fill
			(thermal_gap 0.5)
			(thermal_bridge_width 0.5)
			(island_removal_mode 0)
		)
		(polygon
			(pts
				(xy 424.919394 -229.926388) (xy 426.951394 -229.926388) (xy 426.951394 -230.154988) (xy 424.919394 -230.154988)
				(xy 424.78325 -230.154988) (xy 424.73626 -230.154988) (xy 424.73626 -229.926388) (xy 424.78325 -229.926388)
			)
		)
	)
	(zone
		(layer "F.Cu")
		(hatch none 0.5)
		(connect_pads
			(clearance 0)
		)
		(min_thickness 0.25)
		(keepout
			(tracks allowed)
			(vias allowed)
			(pads allowed)
			(copperpour allowed)
			(footprints allowed)
		)
		(placement
			(enabled no)
			(sheetname "")
		)
		(fill
			(thermal_gap 0.5)
			(thermal_bridge_width 0.5)
			(island_removal_mode 0)
		)
		(polygon
			(pts
				(xy 262.50011 -208.166462) (xy 262.50011 -207.722724) (xy 264.825226 -207.722724) (xy 264.825226 -208.166462)
			)
		)
	)
	(zone
		(layer "F.Cu")
		(hatch none 0.5)
		(connect_pads
			(clearance 0)
		)
		(min_thickness 0.25)
		(keepout
			(tracks allowed)
			(vias allowed)
			(pads allowed)
			(copperpour allowed)
			(footprints allowed)
		)
		(placement
			(enabled no)
			(sheetname "")
		)
		(fill
			(thermal_gap 0.5)
			(thermal_bridge_width 0.5)
			(island_removal_mode 0)
		)
		(polygon
			(pts
				(xy 335.892394 -336.318606) (xy 334.076294 -336.318606) (xy 334.076294 -334.939386) (xy 335.892394 -334.939386)
			)
		)
	)
	(zone
		(layer "F.Cu")
		(hatch none 0.5)
		(connect_pads
			(clearance 0)
		)
		(min_thickness 0.25)
		(keepout
			(tracks allowed)
			(vias allowed)
			(pads allowed)
			(copperpour allowed)
			(footprints allowed)
		)
		(placement
			(enabled no)
			(sheetname "")
		)
		(fill
			(thermal_gap 0.5)
			(thermal_bridge_width 0.5)
			(island_removal_mode 0)
		)
		(polygon
			(pts
				(xy 59.822842 -301.666656) (xy 59.822842 -301.222918) (xy 62.147958 -301.222918) (xy 62.147958 -301.666656)
			)
		)
	)
	(zone
		(layer "F.Cu")
		(hatch none 0.5)
		(connect_pads
			(clearance 0)
		)
		(min_thickness 0.25)
		(keepout
			(tracks allowed)
			(vias allowed)
			(pads allowed)
			(copperpour allowed)
			(footprints allowed)
		)
		(placement
			(enabled no)
			(sheetname "")
		)
		(fill
			(thermal_gap 0.5)
			(thermal_bridge_width 0.5)
			(island_removal_mode 0)
		)
		(polygon
			(pts
				(xy 393.754864 -410.948886) (xy 393.754864 -406.105868) (xy 395.63929 -406.105868) (xy 395.63929 -410.948886)
			)
		)
	)
	(zone
		(layer "F.Cu")
		(hatch none 0.5)
		(connect_pads
			(clearance 0)
		)
		(min_thickness 0.25)
		(keepout
			(tracks allowed)
			(vias allowed)
			(pads allowed)
			(copperpour allowed)
			(footprints allowed)
		)
		(placement
			(enabled no)
			(sheetname "")
		)
		(fill
			(thermal_gap 0.5)
			(thermal_bridge_width 0.5)
			(island_removal_mode 0)
		)
		(polygon
			(pts
				(xy 440.006994 -245.454932) (xy 440.006994 -245.226332) (xy 442.038994 -245.226332) (xy 442.038994 -245.454932)
			)
		)
	)
	(zone
		(layer "F.Cu")
		(hatch none 0.5)
		(connect_pads
			(clearance 0)
		)
		(min_thickness 0.25)
		(keepout
			(tracks allowed)
			(vias allowed)
			(pads allowed)
			(copperpour allowed)
			(footprints allowed)
		)
		(placement
			(enabled no)
			(sheetname "")
		)
		(fill
			(thermal_gap 0.5)
			(thermal_bridge_width 0.5)
			(island_removal_mode 0)
		)
		(polygon
			(pts
				(xy 66.248026 -276.16658) (xy 63.875412 -276.16658) (xy 63.815722 -276.16658) (xy 63.815722 -274.923504)
				(xy 66.308224 -274.923504) (xy 66.308224 -276.16658)
			)
		)
	)
	(zone
		(layer "F.Cu")
		(hatch none 0.5)
		(connect_pads
			(clearance 0)
		)
		(min_thickness 0.25)
		(keepout
			(tracks not_allowed)
			(vias allowed)
			(pads allowed)
			(copperpour not_allowed)
			(footprints allowed)
		)
		(placement
			(enabled no)
			(sheetname "")
		)
		(fill
			(thermal_gap 0.5)
			(thermal_bridge_width 0.5)
			(island_removal_mode 0)
		)
		(polygon
			(pts
				(xy 351.29597 -335.364328) (xy 351.29597 -334.358488) (xy 351.053654 -334.358488) (xy 351.053654 -335.422748)
				(xy 351.23755 -335.422748)
			)
		)
	)
	(zone
		(layer "F.Cu")
		(hatch none 0.5)
		(connect_pads
			(clearance 0)
		)
		(min_thickness 0.25)
		(keepout
			(tracks allowed)
			(vias allowed)
			(pads allowed)
			(copperpour allowed)
			(footprints allowed)
		)
		(placement
			(enabled no)
			(sheetname "")
		)
		(fill
			(thermal_gap 0.5)
			(thermal_bridge_width 0.5)
			(island_removal_mode 0)
		)
		(polygon
			(pts
				(xy 336.50174 -289.024568) (xy 336.78876 -289.024568) (xy 336.81924 -288.994088) (xy 336.81924 -288.366708)
				(xy 336.73288 -288.280348) (xy 336.54492 -288.280348) (xy 336.47126 -288.354008) (xy 336.47126 -288.994088)
			)
		)
	)
	(zone
		(layer "F.Cu")
		(hatch none 0.5)
		(connect_pads
			(clearance 0)
		)
		(min_thickness 0.25)
		(keepout
			(tracks allowed)
			(vias allowed)
			(pads allowed)
			(copperpour allowed)
			(footprints allowed)
		)
		(placement
			(enabled no)
			(sheetname "")
		)
		(fill
			(thermal_gap 0.5)
			(thermal_bridge_width 0.5)
			(island_removal_mode 0)
		)
		(polygon
			(pts
				(xy 59.822842 -208.166462) (xy 59.822842 -207.722724) (xy 62.147958 -207.722724) (xy 62.147958 -208.166462)
			)
		)
	)
	(zone
		(layer "F.Cu")
		(hatch none 0.5)
		(connect_pads
			(clearance 0)
		)
		(min_thickness 0.25)
		(keepout
			(tracks allowed)
			(vias allowed)
			(pads allowed)
			(copperpour allowed)
			(footprints allowed)
		)
		(placement
			(enabled no)
			(sheetname "")
		)
		(fill
			(thermal_gap 0.5)
			(thermal_bridge_width 0.5)
			(island_removal_mode 0)
		)
		(polygon
			(pts
				(xy 458.538326 -218.254834) (xy 458.538326 -218.026234) (xy 460.570326 -218.026234) (xy 460.570326 -218.254834)
			)
		)
	)
	(zone
		(layer "F.Cu")
		(hatch none 0.5)
		(connect_pads
			(clearance 0)
		)
		(min_thickness 0.25)
		(keepout
			(tracks allowed)
			(vias allowed)
			(pads allowed)
			(copperpour allowed)
			(footprints allowed)
		)
		(placement
			(enabled no)
			(sheetname "")
		)
		(fill
			(thermal_gap 0.5)
			(thermal_bridge_width 0.5)
			(island_removal_mode 0)
		)
		(polygon
			(pts
				(xy 11.11631 -275.316442) (xy 11.11631 -274.872704) (xy 13.441426 -274.872704) (xy 13.441426 -275.316442)
			)
		)
	)
	(zone
		(layer "F.Cu")
		(hatch none 0.5)
		(connect_pads
			(clearance 0)
		)
		(min_thickness 0.25)
		(keepout
			(tracks allowed)
			(vias allowed)
			(pads allowed)
			(copperpour allowed)
			(footprints allowed)
		)
		(placement
			(enabled no)
			(sheetname "")
		)
		(fill
			(thermal_gap 0.5)
			(thermal_bridge_width 0.5)
			(island_removal_mode 0)
		)
		(polygon
			(pts
				(xy 154.63774 -47.079408) (xy 154.63774 -43.746928) (xy 158.02864 -43.746928) (xy 158.02864 -47.079408)
			)
		)
	)
	(zone
		(layer "F.Cu")
		(hatch none 0.5)
		(connect_pads
			(clearance 0)
		)
		(min_thickness 0.25)
		(keepout
			(tracks allowed)
			(vias allowed)
			(pads allowed)
			(copperpour allowed)
			(footprints allowed)
		)
		(placement
			(enabled no)
			(sheetname "")
		)
		(fill
			(thermal_gap 0.5)
			(thermal_bridge_width 0.5)
			(island_removal_mode 0)
		)
		(polygon
			(pts
				(xy 11.11631 -282.11653) (xy 11.11631 -281.672792) (xy 13.441426 -281.672792) (xy 13.441426 -282.11653)
			)
		)
	)
	(zone
		(layer "F.Cu")
		(hatch none 0.5)
		(connect_pads
			(clearance 0)
		)
		(min_thickness 0.25)
		(keepout
			(tracks allowed)
			(vias allowed)
			(pads allowed)
			(copperpour allowed)
			(footprints allowed)
		)
		(placement
			(enabled no)
			(sheetname "")
		)
		(fill
			(thermal_gap 0.5)
			(thermal_bridge_width 0.5)
			(island_removal_mode 0)
		)
		(polygon
			(pts
				(xy 136.8171 -218.473528) (xy 137.10412 -218.473528) (xy 137.1346 -218.443048) (xy 137.1346 -217.815668)
				(xy 137.04824 -217.729308) (xy 136.86028 -217.729308) (xy 136.78662 -217.802968) (xy 136.78662 -218.443048)
			)
		)
	)
	(zone
		(layer "F.Cu")
		(hatch none 0.5)
		(connect_pads
			(clearance 0)
		)
		(min_thickness 0.25)
		(keepout
			(tracks allowed)
			(vias allowed)
			(pads allowed)
			(copperpour allowed)
			(footprints allowed)
		)
		(placement
			(enabled no)
			(sheetname "")
		)
		(fill
			(thermal_gap 0.5)
			(thermal_bridge_width 0.5)
			(island_removal_mode 0)
		)
		(polygon
			(pts
				(xy 336.768694 -339.369146) (xy 335.021174 -339.369146) (xy 335.021174 -337.433666) (xy 336.768694 -337.433666)
			)
		)
	)
	(zone
		(layer "F.Cu")
		(hatch none 0.5)
		(connect_pads
			(clearance 0)
		)
		(min_thickness 0.25)
		(keepout
			(tracks allowed)
			(vias allowed)
			(pads allowed)
			(copperpour allowed)
			(footprints allowed)
		)
		(placement
			(enabled no)
			(sheetname "")
		)
		(fill
			(thermal_gap 0.5)
			(thermal_bridge_width 0.5)
			(island_removal_mode 0)
		)
		(polygon
			(pts
				(xy 87.01278 -216.886028) (xy 87.2998 -216.886028) (xy 87.33028 -216.855548) (xy 87.33028 -216.228168)
				(xy 87.24392 -216.141808) (xy 87.05596 -216.141808) (xy 86.9823 -216.215468) (xy 86.9823 -216.855548)
			)
		)
	)
	(zone
		(layer "F.Cu")
		(hatch none 0.5)
		(connect_pads
			(clearance 0)
		)
		(min_thickness 0.25)
		(keepout
			(tracks allowed)
			(vias allowed)
			(pads allowed)
			(copperpour allowed)
			(footprints allowed)
		)
		(placement
			(enabled no)
			(sheetname "")
		)
		(fill
			(thermal_gap 0.5)
			(thermal_bridge_width 0.5)
			(island_removal_mode 0)
		)
		(polygon
			(pts
				(xy 14.560042 -217.516456) (xy 14.560042 -217.072718) (xy 16.885158 -217.072718) (xy 16.885158 -217.516456)
			)
		)
	)
	(zone
		(layer "F.Cu")
		(hatch none 0.5)
		(connect_pads
			(clearance 0)
		)
		(min_thickness 0.25)
		(keepout
			(tracks allowed)
			(vias allowed)
			(pads allowed)
			(copperpour allowed)
			(footprints allowed)
		)
		(placement
			(enabled no)
			(sheetname "")
		)
		(fill
			(thermal_gap 0.5)
			(thermal_bridge_width 0.5)
			(island_removal_mode 0)
		)
		(polygon
			(pts
				(xy 307.76291 -220.9165) (xy 307.76291 -220.472762) (xy 310.088026 -220.472762) (xy 310.088026 -220.9165)
			)
		)
	)
	(zone
		(layer "F.Cu")
		(hatch none 0.5)
		(connect_pads
			(clearance 0)
		)
		(min_thickness 0.25)
		(keepout
			(tracks allowed)
			(vias allowed)
			(pads allowed)
			(copperpour allowed)
			(footprints allowed)
		)
		(placement
			(enabled no)
			(sheetname "")
		)
		(fill
			(thermal_gap 0.5)
			(thermal_bridge_width 0.5)
			(island_removal_mode 0)
		)
		(polygon
			(pts
				(xy 413.275526 -310.90489) (xy 413.275526 -310.67629) (xy 415.307526 -310.67629) (xy 415.307526 -310.90489)
			)
		)
	)
	(zone
		(layer "F.Cu")
		(hatch none 0.5)
		(connect_pads
			(clearance 0)
		)
		(min_thickness 0.25)
		(keepout
			(tracks allowed)
			(vias allowed)
			(pads allowed)
			(copperpour allowed)
			(footprints allowed)
		)
		(placement
			(enabled no)
			(sheetname "")
		)
		(fill
			(thermal_gap 0.5)
			(thermal_bridge_width 0.5)
			(island_removal_mode 0)
		)
		(polygon
			(pts
				(xy 63.977012 -265.966448) (xy 63.977012 -265.52271) (xy 66.212212 -265.52271) (xy 66.212212 -265.966448)
			)
		)
	)
	(zone
		(layer "F.Cu")
		(hatch none 0.5)
		(connect_pads
			(clearance 0)
		)
		(min_thickness 0.25)
		(keepout
			(tracks allowed)
			(vias allowed)
			(pads allowed)
			(copperpour allowed)
			(footprints allowed)
		)
		(placement
			(enabled no)
			(sheetname "")
		)
		(fill
			(thermal_gap 0.5)
			(thermal_bridge_width 0.5)
			(island_removal_mode 0)
		)
		(polygon
			(pts
				(xy 262.50011 -269.366492) (xy 262.50011 -268.922754) (xy 264.825226 -268.922754) (xy 264.825226 -269.366492)
			)
		)
	)
	(zone
		(layer "F.Cu")
		(hatch none 0.5)
		(connect_pads
			(clearance 0)
		)
		(min_thickness 0.25)
		(keepout
			(tracks allowed)
			(vias allowed)
			(pads allowed)
			(copperpour allowed)
			(footprints allowed)
		)
		(placement
			(enabled no)
			(sheetname "")
		)
		(fill
			(thermal_gap 0.5)
			(thermal_bridge_width 0.5)
			(island_removal_mode 0)
		)
		(polygon
			(pts
				(xy 56.926226 -145.309082) (xy 52.920646 -145.309082) (xy 52.440586 -145.789142) (xy 52.440586 -147.854162)
				(xy 52.712366 -148.125942) (xy 54.566566 -148.125942) (xy 54.818026 -148.377402) (xy 54.818026 -150.297642)
				(xy 55.234586 -150.714202) (xy 56.725566 -150.714202) (xy 57.373266 -150.066502) (xy 57.373266 -145.756122)
			)
		)
	)
	(zone
		(layer "F.Cu")
		(hatch none 0.5)
		(connect_pads
			(clearance 0)
		)
		(min_thickness 0.25)
		(keepout
			(tracks allowed)
			(vias allowed)
			(pads allowed)
			(copperpour allowed)
			(footprints allowed)
		)
		(placement
			(enabled no)
			(sheetname "")
		)
		(fill
			(thermal_gap 0.5)
			(thermal_bridge_width 0.5)
			(island_removal_mode 0)
		)
		(polygon
			(pts
				(xy 118.946422 -331.689456) (xy 118.946422 -335.695036) (xy 119.426482 -336.175096) (xy 121.491502 -336.175096)
				(xy 121.763282 -335.903316) (xy 121.763282 -334.049116) (xy 122.014742 -333.797656) (xy 123.934982 -333.797656)
				(xy 124.351542 -333.381096) (xy 124.351542 -331.890116) (xy 123.703842 -331.242416) (xy 119.393462 -331.242416)
			)
		)
	)
	(zone
		(layer "F.Cu")
		(hatch none 0.5)
		(connect_pads
			(clearance 0)
		)
		(min_thickness 0.25)
		(keepout
			(tracks allowed)
			(vias allowed)
			(pads allowed)
			(copperpour allowed)
			(footprints allowed)
		)
		(placement
			(enabled no)
			(sheetname "")
		)
		(fill
			(thermal_gap 0.5)
			(thermal_bridge_width 0.5)
			(island_removal_mode 0)
		)
		(polygon
			(pts
				(xy 164.102542 -269.028672) (xy 164.102542 -269.265908) (xy 164.240464 -269.265908) (xy 164.283644 -269.309088)
				(xy 164.283644 -269.44193) (xy 164.283644 -269.745968) (xy 164.211 -269.818612) (xy 161.670746 -269.818612)
				(xy 161.529522 -269.677388) (xy 161.529522 -269.480284) (xy 161.611056 -269.39875) (xy 161.708592 -269.301214)
				(xy 161.708592 -269.026386) (xy 161.708592 -268.470634) (xy 164.87902 -268.470634) (xy 164.87902 -269.178024)
				(xy 164.613336 -269.178024) (xy 164.416232 -268.98092) (xy 164.107368 -268.98092) (xy 164.102542 -268.985746)
			)
		)
	)
	(zone
		(layer "F.Cu")
		(hatch none 0.5)
		(connect_pads
			(clearance 0)
		)
		(min_thickness 0.25)
		(keepout
			(tracks not_allowed)
			(vias allowed)
			(pads allowed)
			(copperpour not_allowed)
			(footprints allowed)
		)
		(placement
			(enabled no)
			(sheetname "")
		)
		(fill
			(thermal_gap 0.5)
			(thermal_bridge_width 0.5)
			(island_removal_mode 0)
		)
		(polygon
			(pts
				(arc
					(start 92.899992 -22.29993)
					(mid 94.899988 -20.299934)
					(end 96.899984 -22.29993)
				)
				(arc
					(start 96.899984 -22.29993)
					(mid 94.899988 -24.299926)
					(end 92.899992 -22.29993)
				)
			)
		)
	)
	(zone
		(layer "F.Cu")
		(hatch none 0.5)
		(connect_pads
			(clearance 0)
		)
		(min_thickness 0.25)
		(keepout
			(tracks allowed)
			(vias allowed)
			(pads allowed)
			(copperpour allowed)
			(footprints allowed)
		)
		(placement
			(enabled no)
			(sheetname "")
		)
		(fill
			(thermal_gap 0.5)
			(thermal_bridge_width 0.5)
			(island_removal_mode 0)
		)
		(polygon
			(pts
				(xy 192.066926 -249.47626) (xy 194.098926 -249.47626) (xy 194.098926 -249.70486) (xy 192.066926 -249.70486)
				(xy 191.900302 -249.70486) (xy 191.900302 -249.47626)
			)
		)
	)
	(zone
		(layer "F.Cu")
		(hatch none 0.5)
		(connect_pads
			(clearance 0)
		)
		(min_thickness 0.25)
		(keepout
			(tracks allowed)
			(vias allowed)
			(pads allowed)
			(copperpour allowed)
			(footprints allowed)
		)
		(placement
			(enabled no)
			(sheetname "")
		)
		(fill
			(thermal_gap 0.5)
			(thermal_bridge_width 0.5)
			(island_removal_mode 0)
		)
		(polygon
			(pts
				(xy 409.831794 -220.804994) (xy 409.831794 -220.576394) (xy 411.863794 -220.576394) (xy 411.863794 -220.804994)
			)
		)
	)
	(zone
		(layer "F.Cu")
		(hatch none 0.5)
		(connect_pads
			(clearance 0)
		)
		(min_thickness 0.25)
		(keepout
			(tracks allowed)
			(vias allowed)
			(pads allowed)
			(copperpour allowed)
			(footprints allowed)
		)
		(placement
			(enabled no)
			(sheetname "")
		)
		(fill
			(thermal_gap 0.5)
			(thermal_bridge_width 0.5)
			(island_removal_mode 0)
		)
		(polygon
			(pts
				(xy 304.319178 -265.116564) (xy 304.319178 -264.672826) (xy 306.644294 -264.672826) (xy 306.644294 -265.116564)
			)
		)
	)
	(zone
		(layer "F.Cu")
		(hatch none 0.5)
		(connect_pads
			(clearance 0)
		)
		(min_thickness 0.25)
		(keepout
			(tracks allowed)
			(vias allowed)
			(pads allowed)
			(copperpour allowed)
			(footprints allowed)
		)
		(placement
			(enabled no)
			(sheetname "")
		)
		(fill
			(thermal_gap 0.5)
			(thermal_bridge_width 0.5)
			(island_removal_mode 0)
		)
		(polygon
			(pts
				(xy 14.560042 -281.266646) (xy 14.560042 -280.822908) (xy 16.885158 -280.822908) (xy 16.885158 -281.266646)
			)
		)
	)
	(zone
		(layer "F.Cu")
		(hatch none 0.5)
		(connect_pads
			(clearance 0)
		)
		(min_thickness 0.25)
		(keepout
			(tracks allowed)
			(vias allowed)
			(pads allowed)
			(copperpour allowed)
			(footprints allowed)
		)
		(placement
			(enabled no)
			(sheetname "")
		)
		(fill
			(thermal_gap 0.5)
			(thermal_bridge_width 0.5)
			(island_removal_mode 0)
		)
		(polygon
			(pts
				(xy 306.586382 -404.802594) (xy 306.586382 -399.959576) (xy 308.470808 -399.959576) (xy 308.470808 -404.802594)
			)
		)
	)
	(zone
		(layer "F.Cu")
		(hatch none 0.5)
		(connect_pads
			(clearance 0)
		)
		(min_thickness 0.25)
		(keepout
			(tracks allowed)
			(vias allowed)
			(pads allowed)
			(copperpour allowed)
			(footprints allowed)
		)
		(placement
			(enabled no)
			(sheetname "")
		)
		(fill
			(thermal_gap 0.5)
			(thermal_bridge_width 0.5)
			(island_removal_mode 0)
		)
		(polygon
			(pts
				(xy 418.252402 -162.19424) (xy 418.252402 -163.94176) (xy 416.316922 -163.94176) (xy 416.316922 -162.19424)
			)
		)
	)
	(zone
		(layer "F.Cu")
		(hatch none 0.5)
		(connect_pads
			(clearance 0)
		)
		(min_thickness 0.25)
		(keepout
			(tracks allowed)
			(vias allowed)
			(pads allowed)
			(copperpour allowed)
			(footprints allowed)
		)
		(placement
			(enabled no)
			(sheetname "")
		)
		(fill
			(thermal_gap 0.5)
			(thermal_bridge_width 0.5)
			(island_removal_mode 0)
		)
		(polygon
			(pts
				(xy 295.941496 -360.748834) (xy 295.941496 -364.754414) (xy 296.421556 -365.234474) (xy 298.486576 -365.234474)
				(xy 298.758356 -364.962694) (xy 298.758356 -363.108494) (xy 299.009816 -362.857034) (xy 300.930056 -362.857034)
				(xy 301.346616 -362.440474) (xy 301.346616 -360.949494) (xy 300.698916 -360.301794) (xy 296.388536 -360.301794)
			)
		)
	)
	(zone
		(layer "F.Cu")
		(hatch none 0.5)
		(connect_pads
			(clearance 0)
		)
		(min_thickness 0.25)
		(keepout
			(tracks allowed)
			(vias allowed)
			(pads allowed)
			(copperpour allowed)
			(footprints allowed)
		)
		(placement
			(enabled no)
			(sheetname "")
		)
		(fill
			(thermal_gap 0.5)
			(thermal_bridge_width 0.5)
			(island_removal_mode 0)
		)
		(polygon
			(pts
				(xy 59.822842 -196.266562) (xy 59.822842 -195.822824) (xy 62.147958 -195.822824) (xy 62.147958 -196.266562)
			)
		)
	)
	(zone
		(layer "F.Cu")
		(hatch none 0.5)
		(connect_pads
			(clearance 0)
		)
		(min_thickness 0.25)
		(keepout
			(tracks allowed)
			(vias allowed)
			(pads allowed)
			(copperpour allowed)
			(footprints allowed)
		)
		(placement
			(enabled no)
			(sheetname "")
		)
		(fill
			(thermal_gap 0.5)
			(thermal_bridge_width 0.5)
			(island_removal_mode 0)
		)
		(polygon
			(pts
				(xy 405.763222 -243.52631) (xy 407.744422 -243.52631) (xy 407.744422 -243.75491) (xy 405.763222 -243.75491)
				(xy 405.535638 -243.75491) (xy 405.535638 -243.52631)
			)
		)
	)
	(zone
		(layer "F.Cu")
		(hatch none 0.5)
		(connect_pads
			(clearance 0)
		)
		(min_thickness 0.25)
		(keepout
			(tracks allowed)
			(vias allowed)
			(pads allowed)
			(copperpour allowed)
			(footprints allowed)
		)
		(placement
			(enabled no)
			(sheetname "")
		)
		(fill
			(thermal_gap 0.5)
			(thermal_bridge_width 0.5)
			(island_removal_mode 0)
		)
		(polygon
			(pts
				(xy 180.423058 -248.854976) (xy 180.423058 -248.626376) (xy 182.455058 -248.626376) (xy 182.455058 -248.854976)
			)
		)
	)
	(zone
		(layer "F.Cu")
		(hatch none 0.5)
		(connect_pads
			(clearance 0)
		)
		(min_thickness 0.25)
		(keepout
			(tracks allowed)
			(vias allowed)
			(pads allowed)
			(copperpour allowed)
			(footprints allowed)
		)
		(placement
			(enabled no)
			(sheetname "")
		)
		(fill
			(thermal_gap 0.5)
			(thermal_bridge_width 0.5)
			(island_removal_mode 0)
		)
		(polygon
			(pts
				(xy 412.04261 -269.028672) (xy 412.04261 -269.265908) (xy 412.180532 -269.265908) (xy 412.223712 -269.309088)
				(xy 412.223712 -269.44193) (xy 412.223712 -269.745968) (xy 412.151068 -269.818612) (xy 409.610814 -269.818612)
				(xy 409.46959 -269.677388) (xy 409.46959 -269.480284) (xy 409.551124 -269.39875) (xy 409.64866 -269.301214)
				(xy 409.64866 -269.026386) (xy 409.64866 -268.470634) (xy 412.819088 -268.470634) (xy 412.819088 -269.178024)
				(xy 412.553404 -269.178024) (xy 412.3563 -268.98092) (xy 412.047436 -268.98092) (xy 412.04261 -268.985746)
			)
		)
	)
	(zone
		(layer "F.Cu")
		(hatch none 0.5)
		(connect_pads
			(clearance 0)
		)
		(min_thickness 0.25)
		(keepout
			(tracks allowed)
			(vias allowed)
			(pads allowed)
			(copperpour allowed)
			(footprints allowed)
		)
		(placement
			(enabled no)
			(sheetname "")
		)
		(fill
			(thermal_gap 0.5)
			(thermal_bridge_width 0.5)
			(island_removal_mode 0)
		)
		(polygon
			(pts
				(xy 424.919394 -237.806992) (xy 426.951394 -237.806992) (xy 426.951394 -237.578392) (xy 424.919394 -237.578392)
				(xy 424.788076 -237.578392) (xy 424.762168 -237.578392) (xy 424.762168 -237.806992) (xy 424.788076 -237.806992)
			)
		)
	)
	(zone
		(layer "F.Cu")
		(hatch none 0.5)
		(connect_pads
			(clearance 0)
		)
		(min_thickness 0.25)
		(keepout
			(tracks allowed)
			(vias allowed)
			(pads allowed)
			(copperpour allowed)
			(footprints allowed)
		)
		(placement
			(enabled no)
			(sheetname "")
		)
		(fill
			(thermal_gap 0.5)
			(thermal_bridge_width 0.5)
			(island_removal_mode 0)
		)
		(polygon
			(pts
				(xy 375.434352 -324.733158) (xy 375.434352 -322.431918) (xy 379.805692 -322.431918) (xy 379.805692 -324.733158)
			)
		)
	)
	(zone
		(layer "F.Cu")
		(hatch none 0.5)
		(connect_pads
			(clearance 0)
		)
		(min_thickness 0.25)
		(keepout
			(tracks allowed)
			(vias allowed)
			(pads allowed)
			(copperpour allowed)
			(footprints allowed)
		)
		(placement
			(enabled no)
			(sheetname "")
		)
		(fill
			(thermal_gap 0.5)
			(thermal_bridge_width 0.5)
			(island_removal_mode 0)
		)
		(polygon
			(pts
				(xy 41.29151 -245.566438) (xy 41.29151 -245.1227) (xy 43.616626 -245.1227) (xy 43.616626 -245.566438)
			)
		)
	)
	(zone
		(layer "F.Cu")
		(hatch none 0.5)
		(connect_pads
			(clearance 0)
		)
		(min_thickness 0.25)
		(keepout
			(tracks allowed)
			(vias allowed)
			(pads allowed)
			(copperpour allowed)
			(footprints allowed)
		)
		(placement
			(enabled no)
			(sheetname "")
		)
		(fill
			(thermal_gap 0.5)
			(thermal_bridge_width 0.5)
			(island_removal_mode 0)
		)
		(polygon
			(pts
				(xy 11.11631 -278.716486) (xy 11.11631 -278.272748) (xy 13.441426 -278.272748) (xy 13.441426 -278.716486)
			)
		)
	)
	(zone
		(layer "F.Cu")
		(hatch none 0.5)
		(connect_pads
			(clearance 0)
		)
		(min_thickness 0.25)
		(keepout
			(tracks allowed)
			(vias allowed)
			(pads allowed)
			(copperpour allowed)
			(footprints allowed)
		)
		(placement
			(enabled no)
			(sheetname "")
		)
		(fill
			(thermal_gap 0.5)
			(thermal_bridge_width 0.5)
			(island_removal_mode 0)
		)
		(polygon
			(pts
				(xy 424.919394 -278.37638) (xy 426.951394 -278.37638) (xy 426.951394 -278.60498) (xy 424.919394 -278.60498)
				(xy 424.78325 -278.60498) (xy 424.73626 -278.60498) (xy 424.73626 -278.37638) (xy 424.78325 -278.37638)
			)
		)
	)
	(zone
		(layer "F.Cu")
		(hatch none 0.5)
		(connect_pads
			(clearance 0)
		)
		(min_thickness 0.25)
		(keepout
			(tracks allowed)
			(vias allowed)
			(pads allowed)
			(copperpour allowed)
			(footprints allowed)
		)
		(placement
			(enabled no)
			(sheetname "")
		)
		(fill
			(thermal_gap 0.5)
			(thermal_bridge_width 0.5)
			(island_removal_mode 0)
		)
		(polygon
			(pts
				(xy 443.450726 -304.95494) (xy 443.450726 -304.72634) (xy 445.482726 -304.72634) (xy 445.482726 -304.95494)
			)
		)
	)
	(zone
		(layer "F.Cu")
		(hatch none 0.5)
		(connect_pads
			(clearance 0)
		)
		(min_thickness 0.25)
		(keepout
			(tracks allowed)
			(vias allowed)
			(pads allowed)
			(copperpour allowed)
			(footprints allowed)
		)
		(placement
			(enabled no)
			(sheetname "")
		)
		(fill
			(thermal_gap 0.5)
			(thermal_bridge_width 0.5)
			(island_removal_mode 0)
		)
		(polygon
			(pts
				(xy 41.29151 -306.766468) (xy 41.29151 -306.32273) (xy 43.616626 -306.32273) (xy 43.616626 -306.766468)
			)
		)
	)
	(zone
		(layer "F.Cu")
		(hatch none 0.5)
		(connect_pads
			(clearance 0)
		)
		(min_thickness 0.25)
		(keepout
			(tracks allowed)
			(vias allowed)
			(pads allowed)
			(copperpour allowed)
			(footprints allowed)
		)
		(placement
			(enabled no)
			(sheetname "")
		)
		(fill
			(thermal_gap 0.5)
			(thermal_bridge_width 0.5)
			(island_removal_mode 0)
		)
		(polygon
			(pts
				(xy 274.143978 -240.872772) (xy 276.469094 -240.872772) (xy 276.53869 -240.872772) (xy 276.53869 -241.83213)
				(xy 274.009866 -241.83213) (xy 274.009866 -240.872772)
			)
		)
	)
	(zone
		(layer "F.Cu")
		(hatch none 0.5)
		(connect_pads
			(clearance 0)
		)
		(min_thickness 0.25)
		(keepout
			(tracks allowed)
			(vias allowed)
			(pads allowed)
			(copperpour allowed)
			(footprints allowed)
		)
		(placement
			(enabled no)
			(sheetname "")
		)
		(fill
			(thermal_gap 0.5)
			(thermal_bridge_width 0.5)
			(island_removal_mode 0)
		)
		(polygon
			(pts
				(xy 274.143978 -262.566658) (xy 274.143978 -262.12292) (xy 276.469094 -262.12292) (xy 276.469094 -262.566658)
			)
		)
	)
	(zone
		(layer "F.Cu")
		(hatch none 0.5)
		(connect_pads
			(clearance 0)
		)
		(min_thickness 0.25)
		(keepout
			(tracks allowed)
			(vias allowed)
			(pads allowed)
			(copperpour allowed)
			(footprints allowed)
		)
		(placement
			(enabled no)
			(sheetname "")
		)
		(fill
			(thermal_gap 0.5)
			(thermal_bridge_width 0.5)
			(island_removal_mode 0)
		)
		(polygon
			(pts
				(xy 26.20391 -228.566472) (xy 26.20391 -228.122734) (xy 28.529026 -228.122734) (xy 28.529026 -228.566472)
			)
		)
	)
	(zone
		(layer "F.Cu")
		(hatch none 0.5)
		(connect_pads
			(clearance 0)
		)
		(min_thickness 0.25)
		(keepout
			(tracks allowed)
			(vias allowed)
			(pads allowed)
			(copperpour allowed)
			(footprints allowed)
		)
		(placement
			(enabled no)
			(sheetname "")
		)
		(fill
			(thermal_gap 0.5)
			(thermal_bridge_width 0.5)
			(island_removal_mode 0)
		)
		(polygon
			(pts
				(xy 38.6715 -393.67968) (xy 38.6715 -391.13206) (xy 41.24198 -391.13206) (xy 41.24198 -393.67968)
			)
		)
	)
	(zone
		(layer "F.Cu")
		(hatch none 0.5)
		(connect_pads
			(clearance 0)
		)
		(min_thickness 0.25)
		(keepout
			(tracks allowed)
			(vias allowed)
			(pads allowed)
			(copperpour allowed)
			(footprints allowed)
		)
		(placement
			(enabled no)
			(sheetname "")
		)
		(fill
			(thermal_gap 0.5)
			(thermal_bridge_width 0.5)
			(island_removal_mode 0)
		)
		(polygon
			(pts
				(xy 29.647642 -220.9165) (xy 29.647642 -220.472762) (xy 31.972758 -220.472762) (xy 31.972758 -220.9165)
			)
		)
	)
	(zone
		(layer "F.Cu")
		(hatch none 0.5)
		(connect_pads
			(clearance 0)
		)
		(min_thickness 0.25)
		(keepout
			(tracks allowed)
			(vias allowed)
			(pads allowed)
			(copperpour allowed)
			(footprints allowed)
		)
		(placement
			(enabled no)
			(sheetname "")
		)
		(fill
			(thermal_gap 0.5)
			(thermal_bridge_width 0.5)
			(island_removal_mode 0)
		)
		(polygon
			(pts
				(xy 292.67531 -231.116632) (xy 292.67531 -230.672894) (xy 295.000426 -230.672894) (xy 295.000426 -231.116632)
			)
		)
	)
	(zone
		(layer "F.Cu")
		(hatch none 0.5)
		(connect_pads
			(clearance 0)
		)
		(min_thickness 0.25)
		(keepout
			(tracks allowed)
			(vias allowed)
			(pads allowed)
			(copperpour allowed)
			(footprints allowed)
		)
		(placement
			(enabled no)
			(sheetname "")
		)
		(fill
			(thermal_gap 0.5)
			(thermal_bridge_width 0.5)
			(island_removal_mode 0)
		)
		(polygon
			(pts
				(xy 409.831794 -249.70486) (xy 409.831794 -249.47626) (xy 411.863794 -249.47626) (xy 411.863794 -249.70486)
			)
		)
	)
	(zone
		(layer "F.Cu")
		(hatch none 0.5)
		(connect_pads
			(clearance 0)
		)
		(min_thickness 0.25)
		(keepout
			(tracks allowed)
			(vias allowed)
			(pads allowed)
			(copperpour allowed)
			(footprints allowed)
		)
		(placement
			(enabled no)
			(sheetname "")
		)
		(fill
			(thermal_gap 0.5)
			(thermal_bridge_width 0.5)
			(island_removal_mode 0)
		)
		(polygon
			(pts
				(xy 304.319178 -306.766468) (xy 304.319178 -306.32273) (xy 306.644294 -306.32273) (xy 306.644294 -306.766468)
			)
		)
	)
	(zone
		(layer "F.Cu")
		(hatch none 0.5)
		(connect_pads
			(clearance 0)
		)
		(min_thickness 0.25)
		(keepout
			(tracks allowed)
			(vias allowed)
			(pads allowed)
			(copperpour allowed)
			(footprints allowed)
		)
		(placement
			(enabled no)
			(sheetname "")
		)
		(fill
			(thermal_gap 0.5)
			(thermal_bridge_width 0.5)
			(island_removal_mode 0)
		)
		(polygon
			(pts
				(xy 255.821942 -252.918722) (xy 255.821942 -194.7418) (xy 256.173986 -194.389756) (xy 313.576208 -194.389756)
				(xy 314.300362 -194.389756) (xy 314.587128 -194.676522) (xy 314.587128 -198.184262) (xy 314.350908 -198.420482)
				(xy 314.350908 -202.255882) (xy 314.510928 -202.415902) (xy 314.84316 -202.748134) (xy 314.84316 -203.68133)
				(xy 314.510928 -204.013562) (xy 314.510928 -204.856842) (xy 314.510928 -205.992222) (xy 314.350908 -206.152242)
				(xy 314.350908 -209.149442) (xy 315.057028 -209.855562) (xy 315.057028 -210.018122) (xy 315.057028 -210.998562)
				(xy 314.879228 -211.176362) (xy 314.584588 -211.471002) (xy 314.584588 -221.465902) (xy 314.584588 -222.431102)
				(xy 314.584588 -223.04121) (xy 314.350908 -223.27489) (xy 314.350908 -232.659682) (xy 314.625228 -232.934002)
				(xy 314.749688 -233.058462) (xy 314.749688 -233.896662) (xy 314.728098 -233.918252) (xy 314.728098 -237.450122)
				(xy 315.399928 -238.121952) (xy 315.399928 -239.098582) (xy 315.214508 -239.284002) (xy 314.350908 -240.147602)
				(xy 314.350908 -252.7427) (xy 313.717178 -253.37643) (xy 256.27965 -253.37643)
			)
		)
	)
	(zone
		(layer "F.Cu")
		(hatch none 0.5)
		(connect_pads
			(clearance 0)
		)
		(min_thickness 0.25)
		(keepout
			(tracks allowed)
			(vias allowed)
			(pads allowed)
			(copperpour allowed)
			(footprints allowed)
		)
		(placement
			(enabled no)
			(sheetname "")
		)
		(fill
			(thermal_gap 0.5)
			(thermal_bridge_width 0.5)
			(island_removal_mode 0)
		)
		(polygon
			(pts
				(xy 428.363126 -300.705012) (xy 428.363126 -300.476412) (xy 430.395126 -300.476412) (xy 430.395126 -300.705012)
			)
		)
	)
	(zone
		(layer "F.Cu")
		(hatch none 0.5)
		(connect_pads
			(clearance 0)
		)
		(min_thickness 0.25)
		(keepout
			(tracks allowed)
			(vias allowed)
			(pads allowed)
			(copperpour allowed)
			(footprints allowed)
		)
		(placement
			(enabled no)
			(sheetname "")
		)
		(fill
			(thermal_gap 0.5)
			(thermal_bridge_width 0.5)
			(island_removal_mode 0)
		)
		(polygon
			(pts
				(xy 367.258854 -321.385184) (xy 367.258854 -319.083944) (xy 371.630194 -319.083944) (xy 371.630194 -321.385184)
			)
		)
	)
	(zone
		(layer "F.Cu")
		(hatch none 0.5)
		(connect_pads
			(clearance 0)
		)
		(min_thickness 0.25)
		(keepout
			(tracks allowed)
			(vias allowed)
			(pads allowed)
			(copperpour allowed)
			(footprints not_allowed)
		)
		(placement
			(enabled no)
			(sheetname "")
		)
		(fill
			(thermal_gap 0.5)
			(thermal_bridge_width 0.5)
			(island_removal_mode 0)
		)
		(polygon
			(pts
				(arc
					(start 461.600042 -435.600094)
					(mid 458.8002 -438.399936)
					(end 456.000104 -435.600094)
				)
				(arc
					(start 456.000104 -435.600094)
					(mid 458.8002 -432.799998)
					(end 461.600042 -435.600094)
				)
			)
		)
	)
	(zone
		(layer "F.Cu")
		(hatch none 0.5)
		(connect_pads
			(clearance 0)
		)
		(min_thickness 0.25)
		(keepout
			(tracks allowed)
			(vias allowed)
			(pads allowed)
			(copperpour allowed)
			(footprints allowed)
		)
		(placement
			(enabled no)
			(sheetname "")
		)
		(fill
			(thermal_gap 0.5)
			(thermal_bridge_width 0.5)
			(island_removal_mode 0)
		)
		(polygon
			(pts
				(xy 413.275526 -277.526496) (xy 415.307526 -277.526496) (xy 415.307526 -277.528782) (xy 415.486342 -277.528782)
				(xy 415.486342 -277.766018) (xy 415.624264 -277.766018) (xy 415.667444 -277.809198) (xy 415.667444 -277.94204)
				(xy 415.667444 -278.246078) (xy 415.5948 -278.318722) (xy 413.054546 -278.318722) (xy 412.913322 -278.177498)
				(xy 412.913322 -277.980394) (xy 412.994856 -277.89886) (xy 412.994856 -277.526496) (xy 413.092392 -277.526496)
				(xy 413.139382 -277.526496)
			)
		)
	)
	(zone
		(layers "F.Cu" "B.Cu")
		(hatch none 0.5)
		(connect_pads
			(clearance 0)
		)
		(min_thickness 0.25)
		(keepout
			(tracks allowed)
			(vias allowed)
			(pads allowed)
			(copperpour allowed)
			(footprints allowed)
		)
		(placement
			(enabled no)
			(sheetname "")
		)
		(fill yes
			(thermal_gap 0.5)
			(thermal_bridge_width 0.5)
			(island_removal_mode 0)
		)
		(polygon
			(pts
				(xy 275.938488 3.299714) (xy 275.938488 8.137398) (xy 279.304242 8.137398) (xy 279.304242 3.299714)
			)
		)
	)
	(zone
		(layers "F.Cu" "B.Cu")
		(hatch none 0.5)
		(connect_pads
			(clearance 0)
		)
		(min_thickness 0.25)
		(keepout
			(tracks allowed)
			(vias allowed)
			(pads allowed)
			(copperpour allowed)
			(footprints allowed)
		)
		(placement
			(enabled no)
			(sheetname "")
		)
		(fill yes
			(thermal_gap 0.5)
			(thermal_bridge_width 0.5)
			(island_removal_mode 0)
		)
		(polygon
			(pts
				(xy 26.001726 -159.084772) (xy 37.490146 -159.084772) (xy 38.168326 -158.406592) (xy 38.168326 -149.166072)
				(xy 36.301426 -147.299172) (xy 26.489406 -147.299172) (xy 24.708866 -149.079712) (xy 24.708866 -157.791912)
			)
		)
	)
	(zone
		(layers "F.Cu" "B.Cu")
		(hatch none 0.5)
		(connect_pads
			(clearance 0)
		)
		(min_thickness 0.25)
		(keepout
			(tracks allowed)
			(vias allowed)
			(pads allowed)
			(copperpour allowed)
			(footprints allowed)
		)
		(placement
			(enabled no)
			(sheetname "")
		)
		(fill yes
			(thermal_gap 0.5)
			(thermal_bridge_width 0.5)
			(island_removal_mode 0)
		)
		(polygon
			(pts
				(xy 354.524056 3.299714) (xy 354.524056 8.137398) (xy 357.88981 8.137398) (xy 357.88981 3.299714)
			)
		)
	)
	(zone
		(layers "F.Cu" "B.Cu")
		(hatch none 0.5)
		(connect_pads
			(clearance 0)
		)
		(min_thickness 0.25)
		(keepout
			(tracks allowed)
			(vias allowed)
			(pads allowed)
			(copperpour allowed)
			(footprints allowed)
		)
		(placement
			(enabled no)
			(sheetname "")
		)
		(fill yes
			(thermal_gap 0.5)
			(thermal_bridge_width 0.5)
			(island_removal_mode 0)
		)
		(polygon
			(pts
				(xy 85.096858 -337.0072) (xy 86.435438 -337.0072) (xy 86.829138 -337.4009) (xy 86.829138 -339.61578)
				(xy 87.019638 -339.80628) (xy 90.565478 -339.80628) (xy 90.781378 -340.02218) (xy 90.781378 -342.18372)
				(xy 90.621358 -342.34374) (xy 85.185758 -342.34374) (xy 84.741258 -341.89924) (xy 84.741258 -337.3628)
			)
		)
	)
	(zone
		(layers "F.Cu" "B.Cu")
		(hatch none 0.5)
		(connect_pads
			(clearance 0)
		)
		(min_thickness 0.25)
		(keepout
			(tracks allowed)
			(vias allowed)
			(pads allowed)
			(copperpour allowed)
			(footprints allowed)
		)
		(placement
			(enabled no)
			(sheetname "")
		)
		(fill yes
			(thermal_gap 0.5)
			(thermal_bridge_width 0.5)
			(island_removal_mode 0)
		)
		(polygon
			(pts
				(xy 157.451552 3.299714) (xy 157.451552 8.137398) (xy 160.817306 8.137398) (xy 160.817306 3.299714)
			)
		)
	)
	(zone
		(layers "F.Cu" "B.Cu")
		(hatch none 0.5)
		(connect_pads
			(clearance 0)
		)
		(min_thickness 0.25)
		(keepout
			(tracks allowed)
			(vias allowed)
			(pads allowed)
			(copperpour allowed)
			(footprints allowed)
		)
		(placement
			(enabled no)
			(sheetname "")
		)
		(fill yes
			(thermal_gap 0.5)
			(thermal_bridge_width 0.5)
			(island_removal_mode 0)
		)
		(polygon
			(pts
				(xy 285.718504 -1.780286) (xy 285.718504 3.057398) (xy 289.084258 3.057398) (xy 289.084258 -1.780286)
			)
		)
	)
	(zone
		(layers "F.Cu" "B.Cu")
		(hatch none 0.5)
		(connect_pads
			(clearance 0)
		)
		(min_thickness 0.25)
		(keepout
			(tracks allowed)
			(vias allowed)
			(pads allowed)
			(copperpour allowed)
			(footprints allowed)
		)
		(placement
			(enabled no)
			(sheetname "")
		)
		(fill yes
			(thermal_gap 0.5)
			(thermal_bridge_width 0.5)
			(island_removal_mode 0)
		)
		(polygon
			(pts
				(xy 354.524056 -6.860286) (xy 354.524056 -2.022602) (xy 357.88981 -2.022602) (xy 357.88981 -6.860286)
			)
		)
	)
	(zone
		(layers "F.Cu" "B.Cu")
		(hatch none 0.5)
		(connect_pads
			(clearance 0)
		)
		(min_thickness 0.25)
		(keepout
			(tracks allowed)
			(vias allowed)
			(pads allowed)
			(copperpour allowed)
			(footprints allowed)
		)
		(placement
			(enabled no)
			(sheetname "")
		)
		(fill yes
			(thermal_gap 0.5)
			(thermal_bridge_width 0.5)
			(island_removal_mode 0)
		)
		(polygon
			(pts
				(xy 285.718504 3.299714) (xy 285.718504 8.137398) (xy 289.084258 8.137398) (xy 289.084258 3.299714)
			)
		)
	)
	(zone
		(layers "F.Cu" "B.Cu")
		(hatch none 0.5)
		(connect_pads
			(clearance 0)
		)
		(min_thickness 0.25)
		(keepout
			(tracks allowed)
			(vias allowed)
			(pads allowed)
			(copperpour allowed)
			(footprints allowed)
		)
		(placement
			(enabled no)
			(sheetname "")
		)
		(fill yes
			(thermal_gap 0.5)
			(thermal_bridge_width 0.5)
			(island_removal_mode 0)
		)
		(polygon
			(pts
				(xy 333.036672 -337.0072) (xy 334.375252 -337.0072) (xy 334.768952 -337.4009) (xy 334.768952 -339.61578)
				(xy 334.959452 -339.80628) (xy 338.505292 -339.80628) (xy 338.721192 -340.02218) (xy 338.721192 -342.18372)
				(xy 338.561172 -342.34374) (xy 333.125572 -342.34374) (xy 332.681072 -341.89924) (xy 332.681072 -337.3628)
			)
		)
	)
	(zone
		(layers "F.Cu" "B.Cu")
		(hatch none 0.5)
		(connect_pads
			(clearance 0)
		)
		(min_thickness 0.25)
		(keepout
			(tracks allowed)
			(vias allowed)
			(pads allowed)
			(copperpour allowed)
			(footprints not_allowed)
		)
		(placement
			(enabled no)
			(sheetname "")
		)
		(fill yes
			(thermal_gap 0.5)
			(thermal_bridge_width 0.5)
			(island_removal_mode 0)
		)
		(polygon
			(pts
				(xy 473.300044 -113.47069) (xy 465.30006 -113.47069) (xy 465.30006 -102.470712) (xy 473.300044 -102.470712)
			)
		)
	)
	(zone
		(layers "F.Cu" "B.Cu")
		(hatch none 0.5)
		(connect_pads
			(clearance 0)
		)
		(min_thickness 0.25)
		(keepout
			(tracks not_allowed)
			(vias allowed)
			(pads allowed)
			(copperpour not_allowed)
			(footprints allowed)
		)
		(placement
			(enabled no)
			(sheetname "")
		)
		(fill yes
			(thermal_gap 0.5)
			(thermal_bridge_width 0.5)
			(island_removal_mode 0)
		)
		(polygon
			(pts
				(arc
					(start 467.250018 -32.29991)
					(mid 464.75015 -29.800042)
					(end 462.250028 -32.29991)
				)
				(arc
					(start 462.250028 -33.90011)
					(mid 464.75015 -36.400232)
					(end 467.250018 -33.90011)
				)
			)
		)
	)
	(zone
		(layers "F.Cu" "B.Cu")
		(hatch none 0.5)
		(connect_pads
			(clearance 0)
		)
		(min_thickness 0.25)
		(keepout
			(tracks allowed)
			(vias allowed)
			(pads allowed)
			(copperpour allowed)
			(footprints not_allowed)
		)
		(placement
			(enabled no)
			(sheetname "")
		)
		(fill yes
			(thermal_gap 0.5)
			(thermal_bridge_width 0.5)
			(island_removal_mode 0)
		)
		(polygon
			(pts
				(xy 473.300044 -203.14412) (xy 465.30006 -203.14412) (xy 465.30006 -192.144142) (xy 473.300044 -192.144142)
			)
		)
	)
	(zone
		(layers "F.Cu" "B.Cu")
		(hatch none 0.5)
		(connect_pads
			(clearance 0)
		)
		(min_thickness 0.25)
		(keepout
			(tracks allowed)
			(vias allowed)
			(pads allowed)
			(copperpour allowed)
			(footprints allowed)
		)
		(placement
			(enabled no)
			(sheetname "")
		)
		(fill yes
			(thermal_gap 0.5)
			(thermal_bridge_width 0.5)
			(island_removal_mode 0)
		)
		(polygon
			(pts
				(xy 101.444806 -333.45755) (xy 102.783386 -333.45755) (xy 103.177086 -333.85125) (xy 103.177086 -336.06613)
				(xy 103.367586 -336.25663) (xy 106.913426 -336.25663) (xy 107.129326 -336.47253) (xy 107.129326 -338.63407)
				(xy 106.969306 -338.79409) (xy 101.533706 -338.79409) (xy 101.089206 -338.34959) (xy 101.089206 -333.81315)
			)
		)
	)
	(zone
		(layers "F.Cu" "B.Cu")
		(hatch none 0.5)
		(connect_pads
			(clearance 0)
		)
		(min_thickness 0.25)
		(keepout
			(tracks allowed)
			(vias allowed)
			(pads allowed)
			(copperpour allowed)
			(footprints allowed)
		)
		(placement
			(enabled no)
			(sheetname "")
		)
		(fill yes
			(thermal_gap 0.5)
			(thermal_bridge_width 0.5)
			(island_removal_mode 0)
		)
		(polygon
			(pts
				(xy 226.257104 3.299714) (xy 226.257104 8.137398) (xy 229.622858 8.137398) (xy 229.622858 3.299714)
			)
		)
	)
	(zone
		(layers "F.Cu" "B.Cu")
		(hatch none 0.5)
		(connect_pads
			(clearance 0)
		)
		(min_thickness 0.25)
		(keepout
			(tracks allowed)
			(vias allowed)
			(pads allowed)
			(copperpour allowed)
			(footprints allowed)
		)
		(placement
			(enabled no)
			(sheetname "")
		)
		(fill yes
			(thermal_gap 0.5)
			(thermal_bridge_width 0.5)
			(island_removal_mode 0)
		)
		(polygon
			(pts
				(xy 125.899418 -337.0072) (xy 127.237998 -337.0072) (xy 127.631698 -337.4009) (xy 127.631698 -339.61578)
				(xy 127.822198 -339.80628) (xy 131.368038 -339.80628) (xy 131.583938 -340.02218) (xy 131.583938 -342.18372)
				(xy 131.423918 -342.34374) (xy 125.988318 -342.34374) (xy 125.543818 -341.89924) (xy 125.543818 -337.3628)
			)
		)
	)
	(zone
		(layers "F.Cu" "B.Cu")
		(hatch none 0.5)
		(connect_pads
			(clearance 0)
		)
		(min_thickness 0.25)
		(keepout
			(tracks allowed)
			(vias allowed)
			(pads allowed)
			(copperpour allowed)
			(footprints allowed)
		)
		(placement
			(enabled no)
			(sheetname "")
		)
		(fill yes
			(thermal_gap 0.5)
			(thermal_bridge_width 0.5)
			(island_removal_mode 0)
		)
		(polygon
			(pts
				(xy 236.03712 -6.860286) (xy 236.03712 -2.022602) (xy 239.402874 -2.022602) (xy 239.402874 -6.860286)
			)
		)
	)
	(zone
		(layers "F.Cu" "B.Cu")
		(hatch none 0.5)
		(connect_pads
			(clearance 0)
		)
		(min_thickness 0.25)
		(keepout
			(tracks allowed)
			(vias allowed)
			(pads allowed)
			(copperpour allowed)
			(footprints allowed)
		)
		(placement
			(enabled no)
			(sheetname "")
		)
		(fill yes
			(thermal_gap 0.5)
			(thermal_bridge_width 0.5)
			(island_removal_mode 0)
		)
		(polygon
			(pts
				(xy 117.738906 -333.455518) (xy 119.077486 -333.455518) (xy 119.471186 -333.849218) (xy 119.471186 -336.064098)
				(xy 119.661686 -336.254598) (xy 123.207526 -336.254598) (xy 123.423426 -336.470498) (xy 123.423426 -338.632038)
				(xy 123.263406 -338.792058) (xy 117.827806 -338.792058) (xy 117.383306 -338.347558) (xy 117.383306 -333.811118)
			)
		)
	)
	(zone
		(layers "F.Cu" "B.Cu")
		(hatch none 0.5)
		(connect_pads
			(clearance 0)
		)
		(min_thickness 0.25)
		(keepout
			(tracks allowed)
			(vias allowed)
			(pads allowed)
			(copperpour allowed)
			(footprints not_allowed)
		)
		(placement
			(enabled no)
			(sheetname "")
		)
		(fill yes
			(thermal_gap 0.5)
			(thermal_bridge_width 0.5)
			(island_removal_mode 0)
		)
		(polygon
			(pts
				(xy 470.30005 -424.609006) (xy 462.300066 -424.609006) (xy 462.300066 -413.609028) (xy 470.30005 -413.609028)
			)
		)
	)
	(zone
		(layers "F.Cu" "B.Cu")
		(hatch none 0.5)
		(connect_pads
			(clearance 0)
		)
		(min_thickness 0.25)
		(keepout
			(tracks allowed)
			(vias allowed)
			(pads allowed)
			(copperpour allowed)
			(footprints not_allowed)
		)
		(placement
			(enabled no)
			(sheetname "")
		)
		(fill yes
			(thermal_gap 0.5)
			(thermal_bridge_width 0.5)
			(island_removal_mode 0)
		)
		(polygon
			(pts
				(xy 20.580858 -446.989962) (xy 20.580858 -438.989978) (xy 31.580836 -438.989978) (xy 31.580836 -446.989962)
			)
		)
	)
	(zone
		(layers "F.Cu" "B.Cu")
		(hatch none 0.5)
		(connect_pads
			(clearance 0)
		)
		(min_thickness 0.25)
		(keepout
			(tracks allowed)
			(vias allowed)
			(pads allowed)
			(copperpour allowed)
			(footprints not_allowed)
		)
		(placement
			(enabled no)
			(sheetname "")
		)
		(fill yes
			(thermal_gap 0.5)
			(thermal_bridge_width 0.5)
			(island_removal_mode 0)
		)
		(polygon
			(pts
				(xy 473.300044 -148.87702) (xy 465.30006 -148.87702) (xy 465.30006 -137.877042) (xy 473.300044 -137.877042)
			)
		)
	)
	(zone
		(layers "F.Cu" "B.Cu")
		(hatch none 0.5)
		(connect_pads
			(clearance 0)
		)
		(min_thickness 0.25)
		(keepout
			(tracks allowed)
			(vias allowed)
			(pads allowed)
			(copperpour allowed)
			(footprints not_allowed)
		)
		(placement
			(enabled no)
			(sheetname "")
		)
		(fill yes
			(thermal_gap 0.5)
			(thermal_bridge_width 0.5)
			(island_removal_mode 0)
		)
		(polygon
			(pts
				(xy 473.300044 -323.711824) (xy 465.30006 -323.711824) (xy 465.30006 -312.711846) (xy 473.300044 -312.711846)
			)
		)
	)
	(zone
		(layers "F.Cu" "B.Cu")
		(hatch none 0.5)
		(connect_pads
			(clearance 0)
		)
		(min_thickness 0.25)
		(keepout
			(tracks allowed)
			(vias allowed)
			(pads allowed)
			(copperpour allowed)
			(footprints allowed)
		)
		(placement
			(enabled no)
			(sheetname "")
		)
		(fill yes
			(thermal_gap 0.5)
			(thermal_bridge_width 0.5)
			(island_removal_mode 0)
		)
		(polygon
			(pts
				(xy 147.671536 3.299714) (xy 147.671536 8.137398) (xy 151.03729 8.137398) (xy 151.03729 3.299714)
			)
		)
	)
	(zone
		(layers "F.Cu" "B.Cu")
		(hatch none 0.5)
		(connect_pads
			(clearance 0)
		)
		(min_thickness 0.25)
		(keepout
			(tracks allowed)
			(vias allowed)
			(pads allowed)
			(copperpour allowed)
			(footprints allowed)
		)
		(placement
			(enabled no)
			(sheetname "")
		)
		(fill yes
			(thermal_gap 0.5)
			(thermal_bridge_width 0.5)
			(island_removal_mode 0)
		)
		(polygon
			(pts
				(xy 134.05993 -342.797892) (xy 135.39851 -342.797892) (xy 135.79221 -343.191592) (xy 135.79221 -345.406472)
				(xy 135.98271 -345.596972) (xy 139.52855 -345.596972) (xy 139.74445 -345.812872) (xy 139.74445 -347.974412)
				(xy 139.58443 -348.134432) (xy 134.14883 -348.134432) (xy 133.70433 -347.689932) (xy 133.70433 -343.153492)
			)
		)
	)
	(zone
		(layers "F.Cu" "B.Cu")
		(hatch none 0.5)
		(connect_pads
			(clearance 0)
		)
		(min_thickness 0.25)
		(keepout
			(tracks allowed)
			(vias allowed)
			(pads allowed)
			(copperpour allowed)
			(footprints allowed)
		)
		(placement
			(enabled no)
			(sheetname "")
		)
		(fill yes
			(thermal_gap 0.5)
			(thermal_bridge_width 0.5)
			(island_removal_mode 0)
		)
		(polygon
			(pts
				(xy 236.03712 3.299714) (xy 236.03712 8.137398) (xy 239.402874 8.137398) (xy 239.402874 3.299714)
			)
		)
	)
	(zone
		(layers "F.Cu" "B.Cu")
		(hatch none 0.5)
		(connect_pads
			(clearance 0)
		)
		(min_thickness 0.25)
		(keepout
			(tracks allowed)
			(vias allowed)
			(pads allowed)
			(copperpour allowed)
			(footprints allowed)
		)
		(placement
			(enabled no)
			(sheetname "")
		)
		(fill yes
			(thermal_gap 0.5)
			(thermal_bridge_width 0.5)
			(island_removal_mode 0)
		)
		(polygon
			(pts
				(xy 109.514132 -333.45755) (xy 110.852712 -333.45755) (xy 111.246412 -333.85125) (xy 111.246412 -336.06613)
				(xy 111.436912 -336.25663) (xy 114.982752 -336.25663) (xy 115.198652 -336.47253) (xy 115.198652 -338.63407)
				(xy 115.038632 -338.79409) (xy 109.603032 -338.79409) (xy 109.158532 -338.34959) (xy 109.158532 -333.81315)
			)
		)
	)
	(zone
		(layers "F.Cu" "B.Cu")
		(hatch none 0.5)
		(connect_pads
			(clearance 0)
		)
		(min_thickness 0.25)
		(keepout
			(tracks allowed)
			(vias allowed)
			(pads allowed)
			(copperpour allowed)
			(footprints allowed)
		)
		(placement
			(enabled no)
			(sheetname "")
		)
		(fill yes
			(thermal_gap 0.5)
			(thermal_bridge_width 0.5)
			(island_removal_mode 0)
		)
		(polygon
			(pts
				(xy 354.524056 -1.780286) (xy 354.524056 3.057398) (xy 357.88981 3.057398) (xy 357.88981 -1.780286)
			)
		)
	)
	(zone
		(layers "F.Cu" "B.Cu")
		(hatch none 0.5)
		(connect_pads
			(clearance 0)
		)
		(min_thickness 0.25)
		(keepout
			(tracks allowed)
			(vias allowed)
			(pads allowed)
			(copperpour allowed)
			(footprints allowed)
		)
		(placement
			(enabled no)
			(sheetname "")
		)
		(fill yes
			(thermal_gap 0.5)
			(thermal_bridge_width 0.5)
			(island_removal_mode 0)
		)
		(polygon
			(pts
				(xy 285.718504 -6.860286) (xy 285.718504 -2.022602) (xy 289.084258 -2.022602) (xy 289.084258 -6.860286)
			)
		)
	)
	(zone
		(layers "F.Cu" "B.Cu")
		(hatch none 0.5)
		(connect_pads
			(clearance 0)
		)
		(min_thickness 0.25)
		(keepout
			(tracks allowed)
			(vias allowed)
			(pads allowed)
			(copperpour allowed)
			(footprints not_allowed)
		)
		(placement
			(enabled no)
			(sheetname "")
		)
		(fill yes
			(thermal_gap 0.5)
			(thermal_bridge_width 0.5)
			(island_removal_mode 0)
		)
		(polygon
			(pts
				(xy 476.79991 -57.236614) (xy 468.799926 -57.236614) (xy 468.799926 -46.236636) (xy 476.79991 -46.236636)
			)
		)
	)
	(zone
		(layers "F.Cu" "B.Cu")
		(hatch none 0.5)
		(connect_pads
			(clearance 0)
		)
		(min_thickness 0.25)
		(keepout
			(tracks allowed)
			(vias allowed)
			(pads allowed)
			(copperpour allowed)
			(footprints allowed)
		)
		(placement
			(enabled no)
			(sheetname "")
		)
		(fill yes
			(thermal_gap 0.5)
			(thermal_bridge_width 0.5)
			(island_removal_mode 0)
		)
		(polygon
			(pts
				(xy 107.770168 3.299714) (xy 107.770168 8.137398) (xy 111.135922 8.137398) (xy 111.135922 3.299714)
			)
		)
	)
	(zone
		(layers "F.Cu" "B.Cu")
		(hatch none 0.5)
		(connect_pads
			(clearance 0)
		)
		(min_thickness 0.25)
		(keepout
			(tracks allowed)
			(vias allowed)
			(pads allowed)
			(copperpour allowed)
			(footprints not_allowed)
		)
		(placement
			(enabled no)
			(sheetname "")
		)
		(fill yes
			(thermal_gap 0.5)
			(thermal_bridge_width 0.5)
			(island_removal_mode 0)
		)
		(polygon
			(pts
				(xy 473.300044 -257.758184) (xy 465.30006 -257.758184) (xy 465.30006 -246.758206) (xy 473.300044 -246.758206)
			)
		)
	)
	(zone
		(layers "F.Cu" "B.Cu")
		(hatch none 0.5)
		(connect_pads
			(clearance 0)
		)
		(min_thickness 0.25)
		(keepout
			(tracks allowed)
			(vias allowed)
			(pads allowed)
			(copperpour allowed)
			(footprints allowed)
		)
		(placement
			(enabled no)
			(sheetname "")
		)
		(fill yes
			(thermal_gap 0.5)
			(thermal_bridge_width 0.5)
			(island_removal_mode 0)
		)
		(polygon
			(pts
				(xy 275.938488 -1.780286) (xy 275.938488 3.057398) (xy 279.304242 3.057398) (xy 279.304242 -1.780286)
			)
		)
	)
	(zone
		(layers "F.Cu" "B.Cu")
		(hatch none 0.5)
		(connect_pads
			(clearance 0)
		)
		(min_thickness 0.25)
		(keepout
			(tracks allowed)
			(vias allowed)
			(pads allowed)
			(copperpour allowed)
			(footprints allowed)
		)
		(placement
			(enabled no)
			(sheetname "")
		)
		(fill yes
			(thermal_gap 0.5)
			(thermal_bridge_width 0.5)
			(island_removal_mode 0)
		)
		(polygon
			(pts
				(xy 236.03712 -1.780286) (xy 236.03712 3.057398) (xy 239.402874 3.057398) (xy 239.402874 -1.780286)
			)
		)
	)
	(zone
		(layers "F.Cu" "B.Cu")
		(hatch none 0.5)
		(connect_pads
			(clearance 0)
		)
		(min_thickness 0.25)
		(keepout
			(tracks allowed)
			(vias allowed)
			(pads allowed)
			(copperpour allowed)
			(footprints allowed)
		)
		(placement
			(enabled no)
			(sheetname "")
		)
		(fill yes
			(thermal_gap 0.5)
			(thermal_bridge_width 0.5)
			(island_removal_mode 0)
		)
		(polygon
			(pts
				(xy 275.938488 -6.860286) (xy 275.938488 -2.022602) (xy 279.304242 -2.022602) (xy 279.304242 -6.860286)
			)
		)
	)
	(zone
		(layers "F.Cu" "B.Cu")
		(hatch none 0.5)
		(connect_pads
			(clearance 0)
		)
		(min_thickness 0.25)
		(keepout
			(tracks not_allowed)
			(vias allowed)
			(pads allowed)
			(copperpour not_allowed)
			(footprints allowed)
		)
		(placement
			(enabled no)
			(sheetname "")
		)
		(fill yes
			(thermal_gap 0.5)
			(thermal_bridge_width 0.5)
			(island_removal_mode 0)
		)
		(polygon
			(pts
				(arc
					(start 16.010636 -27.306016)
					(mid 12.477047 -27.423809)
					(end 12.594844 -30.957266)
				)
				(arc
					(start 13.763244 -32.050228)
					(mid 17.296697 -31.932563)
					(end 17.179036 -28.398978)
				)
			)
		)
	)
	(zone
		(layers "F.Cu" "B.Cu")
		(hatch none 0.5)
		(connect_pads
			(clearance 0)
		)
		(min_thickness 0.25)
		(keepout
			(tracks allowed)
			(vias allowed)
			(pads allowed)
			(copperpour allowed)
			(footprints not_allowed)
		)
		(placement
			(enabled no)
			(sheetname "")
		)
		(fill yes
			(thermal_gap 0.5)
			(thermal_bridge_width 0.5)
			(island_removal_mode 0)
		)
		(polygon
			(pts
				(xy 473.300044 -380.408434) (xy 465.30006 -380.408434) (xy 465.30006 -369.408456) (xy 473.300044 -369.408456)
			)
		)
	)
	(zone
		(layers "F.Cu" "B.Cu")
		(hatch none 0.5)
		(connect_pads
			(clearance 0)
		)
		(min_thickness 0.25)
		(keepout
			(tracks allowed)
			(vias allowed)
			(pads allowed)
			(copperpour allowed)
			(footprints allowed)
		)
		(placement
			(enabled no)
			(sheetname "")
		)
		(fill yes
			(thermal_gap 0.5)
			(thermal_bridge_width 0.5)
			(island_removal_mode 0)
		)
		(polygon
			(pts
				(xy 76.936346 -342.797892) (xy 78.274926 -342.797892) (xy 78.668626 -343.191592) (xy 78.668626 -345.406472)
				(xy 78.859126 -345.596972) (xy 82.404966 -345.596972) (xy 82.620866 -345.812872) (xy 82.620866 -347.974412)
				(xy 82.460846 -348.134432) (xy 77.025246 -348.134432) (xy 76.580746 -347.689932) (xy 76.580746 -343.153492)
			)
		)
	)
	(zone
		(layers "F.Cu" "B.Cu" "In1.Cu" "In2.Cu" "In3.Cu" "In4.Cu" "In5.Cu" "In6.Cu"
			"In7.Cu" "In8.Cu" "In9.Cu" "In10.Cu" "In11.Cu" "In12.Cu" "In13.Cu" "In14.Cu"
			"In15.Cu" "In16.Cu"
		)
		(hatch none 0.5)
		(connect_pads
			(clearance 0)
		)
		(min_thickness 0.25)
		(keepout
			(tracks not_allowed)
			(vias allowed)
			(pads allowed)
			(copperpour not_allowed)
			(footprints allowed)
		)
		(placement
			(enabled no)
			(sheetname "")
		)
		(fill
			(thermal_gap 0.5)
			(thermal_bridge_width 0.5)
			(island_removal_mode 0)
		)
		(polygon
			(pts
				(arc
					(start 124.607828 -285.759652)
					(mid 124.627512 -285.712242)
					(end 124.634244 -285.661354)
				)
				(arc
					(start 124.634244 -285.661354)
					(mid 124.576588 -285.52216)
					(end 124.437394 -285.464504)
				)
				(arc
					(start 124.437394 -285.464504)
					(mid 124.338963 -285.49092)
					(end 124.26696 -285.563056)
				)
				(arc
					(start 123.797314 -286.377126)
					(mid 123.77763 -286.424536)
					(end 123.770898 -286.475424)
				)
				(arc
					(start 123.770898 -286.475424)
					(mid 123.828554 -286.614618)
					(end 123.967748 -286.672274)
				)
				(arc
					(start 123.967748 -286.672274)
					(mid 124.066179 -286.645858)
					(end 124.138182 -286.573722)
				)
			)
		)
	)
	(zone
		(layers "F.Cu" "B.Cu" "In1.Cu" "In2.Cu" "In3.Cu" "In4.Cu" "In5.Cu" "In6.Cu"
			"In7.Cu" "In8.Cu" "In9.Cu" "In10.Cu" "In11.Cu" "In12.Cu" "In13.Cu" "In14.Cu"
			"In15.Cu" "In16.Cu"
		)
		(hatch none 0.5)
		(connect_pads
			(clearance 0)
		)
		(min_thickness 0.25)
		(keepout
			(tracks not_allowed)
			(vias allowed)
			(pads allowed)
			(copperpour not_allowed)
			(footprints allowed)
		)
		(placement
			(enabled no)
			(sheetname "")
		)
		(fill
			(thermal_gap 0.5)
			(thermal_bridge_width 0.5)
			(island_removal_mode 0)
		)
		(polygon
			(pts
				(arc
					(start 352.500946 -275.08073)
					(mid 351.843086 -275.08073)
					(end 352.500946 -275.08073)
				)
			)
		)
	)
	(zone
		(layers "F.Cu" "B.Cu" "In1.Cu" "In2.Cu" "In3.Cu" "In4.Cu" "In5.Cu" "In6.Cu"
			"In7.Cu" "In8.Cu" "In9.Cu" "In10.Cu" "In11.Cu" "In12.Cu" "In13.Cu" "In14.Cu"
			"In15.Cu" "In16.Cu"
		)
		(hatch none 0.5)
		(connect_pads
			(clearance 0)
		)
		(min_thickness 0.25)
		(keepout
			(tracks not_allowed)
			(vias allowed)
			(pads allowed)
			(copperpour not_allowed)
			(footprints allowed)
		)
		(placement
			(enabled no)
			(sheetname "")
		)
		(fill
			(thermal_gap 0.5)
			(thermal_bridge_width 0.5)
			(island_removal_mode 0)
		)
		(polygon
			(pts
				(arc
					(start 29.816806 -6.343396)
					(mid 29.435806 -6.724396)
					(end 29.816806 -7.105396)
				)
				(arc
					(start 30.680406 -7.105396)
					(mid 31.061406 -6.724396)
					(end 30.680406 -6.343396)
				)
			)
		)
	)
	(zone
		(layers "F.Cu" "B.Cu" "In1.Cu" "In2.Cu" "In3.Cu" "In4.Cu" "In5.Cu" "In6.Cu"
			"In7.Cu" "In8.Cu" "In9.Cu" "In10.Cu" "In11.Cu" "In12.Cu" "In13.Cu" "In14.Cu"
			"In15.Cu" "In16.Cu"
		)
		(hatch none 0.5)
		(connect_pads
			(clearance 0)
		)
		(min_thickness 0.25)
		(keepout
			(tracks not_allowed)
			(vias allowed)
			(pads allowed)
			(copperpour not_allowed)
			(footprints allowed)
		)
		(placement
			(enabled no)
			(sheetname "")
		)
		(fill
			(thermal_gap 0.5)
			(thermal_bridge_width 0.5)
			(island_removal_mode 0)
		)
		(polygon
			(pts
				(arc
					(start 372.908068 -224.291144)
					(mid 372.836079 -224.218985)
					(end 372.737634 -224.192592)
				)
				(arc
					(start 372.737634 -224.192592)
					(mid 372.59844 -224.250248)
					(end 372.540784 -224.389442)
				)
				(arc
					(start 372.540784 -224.389442)
					(mid 372.547541 -224.440323)
					(end 372.5672 -224.48774)
				)
				(arc
					(start 373.036846 -225.301556)
					(mid 373.108835 -225.373715)
					(end 373.20728 -225.400108)
				)
				(arc
					(start 373.20728 -225.400108)
					(mid 373.346474 -225.342452)
					(end 373.40413 -225.203258)
				)
				(arc
					(start 373.40413 -225.203258)
					(mid 373.397373 -225.152377)
					(end 373.377714 -225.10496)
				)
			)
		)
	)
	(zone
		(layers "F.Cu" "B.Cu" "In1.Cu" "In2.Cu" "In3.Cu" "In4.Cu" "In5.Cu" "In6.Cu"
			"In7.Cu" "In8.Cu" "In9.Cu" "In10.Cu" "In11.Cu" "In12.Cu" "In13.Cu" "In14.Cu"
			"In15.Cu" "In16.Cu"
		)
		(hatch none 0.5)
		(connect_pads
			(clearance 0)
		)
		(min_thickness 0.25)
		(keepout
			(tracks not_allowed)
			(vias allowed)
			(pads allowed)
			(copperpour not_allowed)
			(footprints allowed)
		)
		(placement
			(enabled no)
			(sheetname "")
		)
		(fill
			(thermal_gap 0.5)
			(thermal_bridge_width 0.5)
			(island_removal_mode 0)
		)
		(polygon
			(pts
				(arc
					(start 101.113082 -285.563056)
					(mid 101.041093 -285.490897)
					(end 100.942648 -285.464504)
				)
				(arc
					(start 100.942648 -285.464504)
					(mid 100.803454 -285.52216)
					(end 100.745798 -285.661354)
				)
				(arc
					(start 100.745798 -285.661354)
					(mid 100.752555 -285.712235)
					(end 100.772214 -285.759652)
				)
				(arc
					(start 101.242114 -286.573722)
					(mid 101.314103 -286.645881)
					(end 101.412548 -286.672274)
				)
				(arc
					(start 101.412548 -286.672274)
					(mid 101.551742 -286.614618)
					(end 101.609398 -286.475424)
				)
				(arc
					(start 101.609398 -286.475424)
					(mid 101.602641 -286.424543)
					(end 101.582982 -286.377126)
				)
			)
		)
	)
	(zone
		(layers "F.Cu" "B.Cu" "In1.Cu" "In2.Cu" "In3.Cu" "In4.Cu" "In5.Cu" "In6.Cu"
			"In7.Cu" "In8.Cu" "In9.Cu" "In10.Cu" "In11.Cu" "In12.Cu" "In13.Cu" "In14.Cu"
			"In15.Cu" "In16.Cu"
		)
		(hatch none 0.5)
		(connect_pads
			(clearance 0)
		)
		(min_thickness 0.25)
		(keepout
			(tracks not_allowed)
			(vias allowed)
			(pads allowed)
			(copperpour not_allowed)
			(footprints allowed)
		)
		(placement
			(enabled no)
			(sheetname "")
		)
		(fill
			(thermal_gap 0.5)
			(thermal_bridge_width 0.5)
			(island_removal_mode 0)
		)
		(polygon
			(pts
				(arc
					(start 338.763864 -213.732618)
					(mid 338.106004 -213.732618)
					(end 338.763864 -213.732618)
				)
			)
		)
	)
	(zone
		(layers "F.Cu" "B.Cu" "In1.Cu" "In2.Cu" "In3.Cu" "In4.Cu" "In5.Cu" "In6.Cu"
			"In7.Cu" "In8.Cu" "In9.Cu" "In10.Cu" "In11.Cu" "In12.Cu" "In13.Cu" "In14.Cu"
			"In15.Cu" "In16.Cu"
		)
		(hatch none 0.5)
		(connect_pads
			(clearance 0)
		)
		(min_thickness 0.25)
		(keepout
			(tracks not_allowed)
			(vias allowed)
			(pads allowed)
			(copperpour not_allowed)
			(footprints allowed)
		)
		(placement
			(enabled no)
			(sheetname "")
		)
		(fill
			(thermal_gap 0.5)
			(thermal_bridge_width 0.5)
			(island_removal_mode 0)
		)
		(polygon
			(pts
				(arc
					(start 104.560878 -281.59202)
					(mid 103.903018 -281.59202)
					(end 104.560878 -281.59202)
				)
			)
		)
	)
	(zone
		(layers "F.Cu" "B.Cu" "In1.Cu" "In2.Cu" "In3.Cu" "In4.Cu" "In5.Cu" "In6.Cu"
			"In7.Cu" "In8.Cu" "In9.Cu" "In10.Cu" "In11.Cu" "In12.Cu" "In13.Cu" "In14.Cu"
			"In15.Cu" "In16.Cu"
		)
		(hatch none 0.5)
		(connect_pads
			(clearance 0)
		)
		(min_thickness 0.25)
		(keepout
			(tracks not_allowed)
			(vias allowed)
			(pads allowed)
			(copperpour not_allowed)
			(footprints allowed)
		)
		(placement
			(enabled no)
			(sheetname "")
		)
		(fill
			(thermal_gap 0.5)
			(thermal_bridge_width 0.5)
			(island_removal_mode 0)
		)
		(polygon
			(pts
				(arc
					(start 112.750092 -217.97645)
					(mid 112.769776 -217.92904)
					(end 112.776508 -217.878152)
				)
				(arc
					(start 112.776508 -217.878152)
					(mid 112.718852 -217.738958)
					(end 112.579658 -217.681302)
				)
				(arc
					(start 112.579658 -217.681302)
					(mid 112.481227 -217.707718)
					(end 112.409224 -217.779854)
				)
				(arc
					(start 111.939578 -218.593924)
					(mid 111.919894 -218.641334)
					(end 111.913162 -218.692222)
				)
				(arc
					(start 111.913162 -218.692222)
					(mid 111.970818 -218.831416)
					(end 112.110012 -218.889072)
				)
				(arc
					(start 112.110012 -218.889072)
					(mid 112.208443 -218.862656)
					(end 112.280446 -218.79052)
				)
			)
		)
	)
	(zone
		(layers "F.Cu" "B.Cu" "In1.Cu" "In2.Cu" "In3.Cu" "In4.Cu" "In5.Cu" "In6.Cu"
			"In7.Cu" "In8.Cu" "In9.Cu" "In10.Cu" "In11.Cu" "In12.Cu" "In13.Cu" "In14.Cu"
			"In15.Cu" "In16.Cu"
		)
		(hatch none 0.5)
		(connect_pads
			(clearance 0)
		)
		(min_thickness 0.25)
		(keepout
			(tracks not_allowed)
			(vias allowed)
			(pads allowed)
			(copperpour not_allowed)
			(footprints allowed)
		)
		(placement
			(enabled no)
			(sheetname "")
		)
		(fill
			(thermal_gap 0.5)
			(thermal_bridge_width 0.5)
			(island_removal_mode 0)
		)
		(polygon
			(pts
				(arc
					(start 100.5332 -217.780108)
					(mid 100.461211 -217.707949)
					(end 100.362766 -217.681556)
				)
				(arc
					(start 100.362766 -217.681556)
					(mid 100.223572 -217.739212)
					(end 100.165916 -217.878406)
				)
				(arc
					(start 100.165916 -217.878406)
					(mid 100.172673 -217.929287)
					(end 100.192332 -217.976704)
				)
				(arc
					(start 100.661978 -218.79052)
					(mid 100.733967 -218.862679)
					(end 100.832412 -218.889072)
				)
				(arc
					(start 100.832412 -218.889072)
					(mid 100.971606 -218.831416)
					(end 101.029262 -218.692222)
				)
				(arc
					(start 101.029262 -218.692222)
					(mid 101.022505 -218.641341)
					(end 101.002846 -218.593924)
				)
			)
		)
	)
	(zone
		(layers "F.Cu" "B.Cu" "In1.Cu" "In2.Cu" "In3.Cu" "In4.Cu" "In5.Cu" "In6.Cu"
			"In7.Cu" "In8.Cu" "In9.Cu" "In10.Cu" "In11.Cu" "In12.Cu" "In13.Cu" "In14.Cu"
			"In15.Cu" "In16.Cu"
		)
		(hatch none 0.5)
		(connect_pads
			(clearance 0)
		)
		(min_thickness 0.25)
		(keepout
			(tracks not_allowed)
			(vias allowed)
			(pads allowed)
			(copperpour not_allowed)
			(footprints allowed)
		)
		(placement
			(enabled no)
			(sheetname "")
		)
		(fill
			(thermal_gap 0.5)
			(thermal_bridge_width 0.5)
			(island_removal_mode 0)
		)
		(polygon
			(pts
				(arc
					(start 356.93096 -221.231968)
					(mid 356.950644 -221.184558)
					(end 356.957376 -221.13367)
				)
				(arc
					(start 356.957376 -221.13367)
					(mid 356.89972 -220.994476)
					(end 356.760526 -220.93682)
				)
				(arc
					(start 356.760526 -220.93682)
					(mid 356.662095 -220.963236)
					(end 356.590092 -221.035372)
				)
				(arc
					(start 356.120446 -221.849442)
					(mid 356.100762 -221.896852)
					(end 356.09403 -221.94774)
				)
				(arc
					(start 356.09403 -221.94774)
					(mid 356.151686 -222.086934)
					(end 356.29088 -222.14459)
				)
				(arc
					(start 356.29088 -222.14459)
					(mid 356.389311 -222.118174)
					(end 356.461314 -222.046038)
				)
			)
		)
	)
	(zone
		(layers "F.Cu" "B.Cu" "In1.Cu" "In2.Cu" "In3.Cu" "In4.Cu" "In5.Cu" "In6.Cu"
			"In7.Cu" "In8.Cu" "In9.Cu" "In10.Cu" "In11.Cu" "In12.Cu" "In13.Cu" "In14.Cu"
			"In15.Cu" "In16.Cu"
		)
		(hatch none 0.5)
		(connect_pads
			(clearance 0)
		)
		(min_thickness 0.25)
		(keepout
			(tracks not_allowed)
			(vias allowed)
			(pads allowed)
			(copperpour not_allowed)
			(footprints allowed)
		)
		(placement
			(enabled no)
			(sheetname "")
		)
		(fill
			(thermal_gap 0.5)
			(thermal_bridge_width 0.5)
			(island_removal_mode 0)
		)
		(polygon
			(pts
				(arc
					(start 57.169558 -400.477228)
					(mid 56.788558 -400.858228)
					(end 57.169558 -401.239228)
				)
				(arc
					(start 58.033158 -401.239228)
					(mid 58.414158 -400.858228)
					(end 58.033158 -400.477228)
				)
			)
		)
	)
	(zone
		(layers "F.Cu" "B.Cu" "In1.Cu" "In2.Cu" "In3.Cu" "In4.Cu" "In5.Cu" "In6.Cu"
			"In7.Cu" "In8.Cu" "In9.Cu" "In10.Cu" "In11.Cu" "In12.Cu" "In13.Cu" "In14.Cu"
			"In15.Cu" "In16.Cu"
		)
		(hatch none 0.5)
		(connect_pads
			(clearance 0)
		)
		(min_thickness 0.25)
		(keepout
			(tracks not_allowed)
			(vias allowed)
			(pads allowed)
			(copperpour not_allowed)
			(footprints allowed)
		)
		(placement
			(enabled no)
			(sheetname "")
		)
		(fill
			(thermal_gap 0.5)
			(thermal_bridge_width 0.5)
			(island_removal_mode 0)
		)
		(polygon
			(pts
				(arc
					(start 374.831356 -179.067968)
					(mid 375.190566 -178.919178)
					(end 375.339356 -178.559968)
				)
				(arc
					(start 375.339356 -178.559968)
					(mid 375.271299 -178.305971)
					(end 375.085356 -178.12004)
				)
				(arc
					(start 374.161304 -177.586386)
					(mid 374.03901 -177.535849)
					(end 373.907812 -177.518568)
				)
				(arc
					(start 373.907304 -177.518568)
					(mid 373.548094 -177.667358)
					(end 373.399304 -178.026568)
				)
				(arc
					(start 373.399304 -178.026568)
					(mid 373.467361 -178.280565)
					(end 373.653304 -178.466496)
				)
				(arc
					(start 374.577356 -179.00015)
					(mid 374.69965 -179.050687)
					(end 374.830848 -179.067968)
				)
			)
		)
	)
	(zone
		(layers "F.Cu" "B.Cu" "In1.Cu" "In2.Cu" "In3.Cu" "In4.Cu" "In5.Cu" "In6.Cu"
			"In7.Cu" "In8.Cu" "In9.Cu" "In10.Cu" "In11.Cu" "In12.Cu" "In13.Cu" "In14.Cu"
			"In15.Cu" "In16.Cu"
		)
		(hatch none 0.5)
		(connect_pads
			(clearance 0)
		)
		(min_thickness 0.25)
		(keepout
			(tracks not_allowed)
			(vias allowed)
			(pads allowed)
			(copperpour not_allowed)
			(footprints allowed)
		)
		(placement
			(enabled no)
			(sheetname "")
		)
		(fill
			(thermal_gap 0.5)
			(thermal_bridge_width 0.5)
			(island_removal_mode 0)
		)
		(polygon
			(pts
				(arc
					(start 18.327878 -18.75536)
					(mid 17.946878 -19.13636)
					(end 18.327878 -19.51736)
				)
				(arc
					(start 19.191478 -19.51736)
					(mid 19.572478 -19.13636)
					(end 19.191478 -18.75536)
				)
			)
		)
	)
	(zone
		(layers "F.Cu" "B.Cu" "In1.Cu" "In2.Cu" "In3.Cu" "In4.Cu" "In5.Cu" "In6.Cu"
			"In7.Cu" "In8.Cu" "In9.Cu" "In10.Cu" "In11.Cu" "In12.Cu" "In13.Cu" "In14.Cu"
			"In15.Cu" "In16.Cu"
		)
		(hatch none 0.5)
		(connect_pads
			(clearance 0)
		)
		(min_thickness 0.25)
		(keepout
			(tracks not_allowed)
			(vias allowed)
			(pads allowed)
			(copperpour not_allowed)
			(footprints allowed)
		)
		(placement
			(enabled no)
			(sheetname "")
		)
		(fill
			(thermal_gap 0.5)
			(thermal_bridge_width 0.5)
			(island_removal_mode 0)
		)
		(polygon
			(pts
				(arc
					(start 339.70341 -215.436704)
					(mid 339.04555 -215.436704)
					(end 339.70341 -215.436704)
				)
			)
		)
	)
	(zone
		(layers "F.Cu" "B.Cu" "In1.Cu" "In2.Cu" "In3.Cu" "In4.Cu" "In5.Cu" "In6.Cu"
			"In7.Cu" "In8.Cu" "In9.Cu" "In10.Cu" "In11.Cu" "In12.Cu" "In13.Cu" "In14.Cu"
			"In15.Cu" "In16.Cu"
		)
		(hatch none 0.5)
		(connect_pads
			(clearance 0)
		)
		(min_thickness 0.25)
		(keepout
			(tracks not_allowed)
			(vias allowed)
			(pads allowed)
			(copperpour not_allowed)
			(footprints allowed)
		)
		(placement
			(enabled no)
			(sheetname "")
		)
		(fill
			(thermal_gap 0.5)
			(thermal_bridge_width 0.5)
			(island_removal_mode 0)
		)
		(polygon
			(pts
				(arc
					(start 362.258864 -221.94774)
					(mid 361.601004 -221.94774)
					(end 362.258864 -221.94774)
				)
			)
		)
	)
	(zone
		(layers "F.Cu" "B.Cu" "In1.Cu" "In2.Cu" "In3.Cu" "In4.Cu" "In5.Cu" "In6.Cu"
			"In7.Cu" "In8.Cu" "In9.Cu" "In10.Cu" "In11.Cu" "In12.Cu" "In13.Cu" "In14.Cu"
			"In15.Cu" "In16.Cu"
		)
		(hatch none 0.5)
		(connect_pads
			(clearance 0)
		)
		(min_thickness 0.25)
		(keepout
			(tracks not_allowed)
			(vias allowed)
			(pads allowed)
			(copperpour not_allowed)
			(footprints allowed)
		)
		(placement
			(enabled no)
			(sheetname "")
		)
		(fill
			(thermal_gap 0.5)
			(thermal_bridge_width 0.5)
			(island_removal_mode 0)
		)
		(polygon
			(pts
				(arc
					(start 132.00888 -213.646766)
					(mid 131.941172 -213.574915)
					(end 131.846066 -213.548468)
				)
				(arc
					(start 131.846066 -213.548468)
					(mid 131.715852 -213.602404)
					(end 131.661916 -213.732618)
				)
				(arc
					(start 131.661916 -213.732618)
					(mid 131.667367 -213.776839)
					(end 131.683252 -213.81847)
				)
				(arc
					(start 132.152644 -214.708486)
					(mid 132.220352 -214.780337)
					(end 132.315458 -214.806784)
				)
				(arc
					(start 132.315458 -214.806784)
					(mid 132.445672 -214.752848)
					(end 132.499608 -214.622634)
				)
				(arc
					(start 132.499608 -214.622634)
					(mid 132.494157 -214.578413)
					(end 132.478272 -214.536782)
				)
			)
		)
	)
	(zone
		(layers "F.Cu" "B.Cu" "In1.Cu" "In2.Cu" "In3.Cu" "In4.Cu" "In5.Cu" "In6.Cu"
			"In7.Cu" "In8.Cu" "In9.Cu" "In10.Cu" "In11.Cu" "In12.Cu" "In13.Cu" "In14.Cu"
			"In15.Cu" "In16.Cu"
		)
		(hatch none 0.5)
		(connect_pads
			(clearance 0)
		)
		(min_thickness 0.25)
		(keepout
			(tracks not_allowed)
			(vias allowed)
			(pads allowed)
			(copperpour not_allowed)
			(footprints allowed)
		)
		(placement
			(enabled no)
			(sheetname "")
		)
		(fill
			(thermal_gap 0.5)
			(thermal_bridge_width 0.5)
			(island_removal_mode 0)
		)
		(polygon
			(pts
				(arc
					(start 339.014562 -281.39517)
					(mid 338.817712 -281.59202)
					(end 339.014562 -281.78887)
				)
				(arc
					(start 339.954362 -281.78887)
					(mid 340.151212 -281.59202)
					(end 339.954362 -281.39517)
				)
			)
		)
	)
	(zone
		(layers "F.Cu" "B.Cu" "In1.Cu" "In2.Cu" "In3.Cu" "In4.Cu" "In5.Cu" "In6.Cu"
			"In7.Cu" "In8.Cu" "In9.Cu" "In10.Cu" "In11.Cu" "In12.Cu" "In13.Cu" "In14.Cu"
			"In15.Cu" "In16.Cu"
		)
		(hatch none 0.5)
		(connect_pads
			(clearance 0)
		)
		(min_thickness 0.25)
		(keepout
			(tracks not_allowed)
			(vias allowed)
			(pads allowed)
			(copperpour not_allowed)
			(footprints allowed)
		)
		(placement
			(enabled no)
			(sheetname "")
		)
		(fill
			(thermal_gap 0.5)
			(thermal_bridge_width 0.5)
			(island_removal_mode 0)
		)
		(polygon
			(pts
				(arc
					(start 80.142842 -251.76988)
					(mid 75.696826 -251.76988)
					(end 80.142842 -251.76988)
				)
			)
		)
	)
	(zone
		(layers "F.Cu" "B.Cu" "In1.Cu" "In2.Cu" "In3.Cu" "In4.Cu" "In5.Cu" "In6.Cu"
			"In7.Cu" "In8.Cu" "In9.Cu" "In10.Cu" "In11.Cu" "In12.Cu" "In13.Cu" "In14.Cu"
			"In15.Cu" "In16.Cu"
		)
		(hatch none 0.5)
		(connect_pads
			(clearance 0)
		)
		(min_thickness 0.25)
		(keepout
			(tracks not_allowed)
			(vias allowed)
			(pads allowed)
			(copperpour not_allowed)
			(footprints allowed)
		)
		(placement
			(enabled no)
			(sheetname "")
		)
		(fill
			(thermal_gap 0.5)
			(thermal_bridge_width 0.5)
			(island_removal_mode 0)
		)
		(polygon
			(pts
				(arc
					(start 112.20196 -420.056564)
					(mid 112.58296 -419.675564)
					(end 112.20196 -419.294564)
				)
				(arc
					(start 111.33836 -419.294564)
					(mid 110.95736 -419.675564)
					(end 111.33836 -420.056564)
				)
			)
		)
	)
	(zone
		(layers "F.Cu" "B.Cu" "In1.Cu" "In2.Cu" "In3.Cu" "In4.Cu" "In5.Cu" "In6.Cu"
			"In7.Cu" "In8.Cu" "In9.Cu" "In10.Cu" "In11.Cu" "In12.Cu" "In13.Cu" "In14.Cu"
			"In15.Cu" "In16.Cu"
		)
		(hatch none 0.5)
		(connect_pads
			(clearance 0)
		)
		(min_thickness 0.25)
		(keepout
			(tracks not_allowed)
			(vias allowed)
			(pads allowed)
			(copperpour not_allowed)
			(footprints allowed)
		)
		(placement
			(enabled no)
			(sheetname "")
		)
		(fill
			(thermal_gap 0.5)
			(thermal_bridge_width 0.5)
			(island_removal_mode 0)
		)
		(polygon
			(pts
				(arc
					(start 166.103554 -400.477228)
					(mid 165.722554 -400.858228)
					(end 166.103554 -401.239228)
				)
				(arc
					(start 166.967154 -401.239228)
					(mid 167.348154 -400.858228)
					(end 166.967154 -400.477228)
				)
			)
		)
	)
	(zone
		(layers "F.Cu" "B.Cu" "In1.Cu" "In2.Cu" "In3.Cu" "In4.Cu" "In5.Cu" "In6.Cu"
			"In7.Cu" "In8.Cu" "In9.Cu" "In10.Cu" "In11.Cu" "In12.Cu" "In13.Cu" "In14.Cu"
			"In15.Cu" "In16.Cu"
		)
		(hatch none 0.5)
		(connect_pads
			(clearance 0)
		)
		(min_thickness 0.25)
		(keepout
			(tracks not_allowed)
			(vias allowed)
			(pads allowed)
			(copperpour not_allowed)
			(footprints allowed)
		)
		(placement
			(enabled no)
			(sheetname "")
		)
		(fill
			(thermal_gap 0.5)
			(thermal_bridge_width 0.5)
			(island_removal_mode 0)
		)
		(polygon
			(pts
				(arc
					(start 98.183446 -220.418152)
					(mid 98.20313 -220.370742)
					(end 98.209862 -220.319854)
				)
				(arc
					(start 98.209862 -220.319854)
					(mid 98.152206 -220.18066)
					(end 98.013012 -220.123004)
				)
				(arc
					(start 98.013012 -220.123004)
					(mid 97.914581 -220.14942)
					(end 97.842578 -220.221556)
				)
				(arc
					(start 97.372932 -221.035626)
					(mid 97.353248 -221.083036)
					(end 97.346516 -221.133924)
				)
				(arc
					(start 97.346516 -221.133924)
					(mid 97.404172 -221.273118)
					(end 97.543366 -221.330774)
				)
				(arc
					(start 97.543366 -221.330774)
					(mid 97.641797 -221.304358)
					(end 97.7138 -221.232222)
				)
			)
		)
	)
	(zone
		(layers "F.Cu" "B.Cu" "In1.Cu" "In2.Cu" "In3.Cu" "In4.Cu" "In5.Cu" "In6.Cu"
			"In7.Cu" "In8.Cu" "In9.Cu" "In10.Cu" "In11.Cu" "In12.Cu" "In13.Cu" "In14.Cu"
			"In15.Cu" "In16.Cu"
		)
		(hatch none 0.5)
		(connect_pads
			(clearance 0)
		)
		(min_thickness 0.25)
		(keepout
			(tracks not_allowed)
			(vias allowed)
			(pads allowed)
			(copperpour not_allowed)
			(footprints allowed)
		)
		(placement
			(enabled no)
			(sheetname "")
		)
		(fill
			(thermal_gap 0.5)
			(thermal_bridge_width 0.5)
			(island_removal_mode 0)
		)
		(polygon
			(pts
				(arc
					(start 346.862146 -284.847538)
					(mid 346.204286 -284.847538)
					(end 346.862146 -284.847538)
				)
			)
		)
	)
	(zone
		(layers "F.Cu" "B.Cu" "In1.Cu" "In2.Cu" "In3.Cu" "In4.Cu" "In5.Cu" "In6.Cu"
			"In7.Cu" "In8.Cu" "In9.Cu" "In10.Cu" "In11.Cu" "In12.Cu" "In13.Cu" "In14.Cu"
			"In15.Cu" "In16.Cu"
		)
		(hatch none 0.5)
		(connect_pads
			(clearance 0)
		)
		(min_thickness 0.25)
		(keepout
			(tracks not_allowed)
			(vias allowed)
			(pads allowed)
			(copperpour not_allowed)
			(footprints allowed)
		)
		(placement
			(enabled no)
			(sheetname "")
		)
		(fill
			(thermal_gap 0.5)
			(thermal_bridge_width 0.5)
			(island_removal_mode 0)
		)
		(polygon
			(pts
				(arc
					(start 380.11481 -220.319854)
					(mid 379.45695 -220.319854)
					(end 380.11481 -220.319854)
				)
			)
		)
	)
	(zone
		(layers "F.Cu" "B.Cu" "In1.Cu" "In2.Cu" "In3.Cu" "In4.Cu" "In5.Cu" "In6.Cu"
			"In7.Cu" "In8.Cu" "In9.Cu" "In10.Cu" "In11.Cu" "In12.Cu" "In13.Cu" "In14.Cu"
			"In15.Cu" "In16.Cu"
		)
		(hatch none 0.5)
		(connect_pads
			(clearance 0)
		)
		(min_thickness 0.25)
		(keepout
			(tracks not_allowed)
			(vias allowed)
			(pads allowed)
			(copperpour not_allowed)
			(footprints allowed)
		)
		(placement
			(enabled no)
			(sheetname "")
		)
		(fill
			(thermal_gap 0.5)
			(thermal_bridge_width 0.5)
			(island_removal_mode 0)
		)
		(polygon
			(pts
				(arc
					(start 375.41581 -221.94774)
					(mid 374.75795 -221.94774)
					(end 375.41581 -221.94774)
				)
			)
		)
	)
	(zone
		(layers "F.Cu" "B.Cu" "In1.Cu" "In2.Cu" "In3.Cu" "In4.Cu" "In5.Cu" "In6.Cu"
			"In7.Cu" "In8.Cu" "In9.Cu" "In10.Cu" "In11.Cu" "In12.Cu" "In13.Cu" "In14.Cu"
			"In15.Cu" "In16.Cu"
		)
		(hatch none 0.5)
		(connect_pads
			(clearance 0)
		)
		(min_thickness 0.25)
		(keepout
			(tracks not_allowed)
			(vias allowed)
			(pads allowed)
			(copperpour not_allowed)
			(footprints allowed)
		)
		(placement
			(enabled no)
			(sheetname "")
		)
		(fill
			(thermal_gap 0.5)
			(thermal_bridge_width 0.5)
			(island_removal_mode 0)
		)
		(polygon
			(pts
				(arc
					(start 244.83822 -135.092948)
					(mid 244.45722 -135.473948)
					(end 244.83822 -135.854948)
				)
				(arc
					(start 245.70182 -135.854948)
					(mid 246.08282 -135.473948)
					(end 245.70182 -135.092948)
				)
			)
		)
	)
	(zone
		(layers "F.Cu" "B.Cu" "In1.Cu" "In2.Cu" "In3.Cu" "In4.Cu" "In5.Cu" "In6.Cu"
			"In7.Cu" "In8.Cu" "In9.Cu" "In10.Cu" "In11.Cu" "In12.Cu" "In13.Cu" "In14.Cu"
			"In15.Cu" "In16.Cu"
		)
		(hatch none 0.5)
		(connect_pads
			(clearance 0)
		)
		(min_thickness 0.25)
		(keepout
			(tracks not_allowed)
			(vias allowed)
			(pads allowed)
			(copperpour not_allowed)
			(footprints allowed)
		)
		(placement
			(enabled no)
			(sheetname "")
		)
		(fill
			(thermal_gap 0.5)
			(thermal_bridge_width 0.5)
			(island_removal_mode 0)
		)
		(polygon
			(pts
				(arc
					(start 366.799622 -216.966292)
					(mid 366.727633 -216.894133)
					(end 366.629188 -216.86774)
				)
				(arc
					(start 366.629188 -216.86774)
					(mid 366.489994 -216.925396)
					(end 366.432338 -217.06459)
				)
				(arc
					(start 366.432338 -217.06459)
					(mid 366.439095 -217.115471)
					(end 366.458754 -217.162888)
				)
				(arc
					(start 366.9284 -217.976704)
					(mid 367.000389 -218.048863)
					(end 367.098834 -218.075256)
				)
				(arc
					(start 367.098834 -218.075256)
					(mid 367.238028 -218.0176)
					(end 367.295684 -217.878406)
				)
				(arc
					(start 367.295684 -217.878406)
					(mid 367.288927 -217.827525)
					(end 367.269268 -217.780108)
				)
			)
		)
	)
	(zone
		(layers "F.Cu" "B.Cu" "In1.Cu" "In2.Cu" "In3.Cu" "In4.Cu" "In5.Cu" "In6.Cu"
			"In7.Cu" "In8.Cu" "In9.Cu" "In10.Cu" "In11.Cu" "In12.Cu" "In13.Cu" "In14.Cu"
			"In15.Cu" "In16.Cu"
		)
		(hatch none 0.5)
		(connect_pads
			(clearance 0)
		)
		(min_thickness 0.25)
		(keepout
			(tracks not_allowed)
			(vias allowed)
			(pads allowed)
			(copperpour not_allowed)
			(footprints allowed)
		)
		(placement
			(enabled no)
			(sheetname "")
		)
		(fill
			(thermal_gap 0.5)
			(thermal_bridge_width 0.5)
			(island_removal_mode 0)
		)
		(polygon
			(pts
				(arc
					(start 371.296946 -284.847538)
					(mid 370.639086 -284.847538)
					(end 371.296946 -284.847538)
				)
			)
		)
	)
	(zone
		(layers "F.Cu" "B.Cu" "In1.Cu" "In2.Cu" "In3.Cu" "In4.Cu" "In5.Cu" "In6.Cu"
			"In7.Cu" "In8.Cu" "In9.Cu" "In10.Cu" "In11.Cu" "In12.Cu" "In13.Cu" "In14.Cu"
			"In15.Cu" "In16.Cu"
		)
		(hatch none 0.5)
		(connect_pads
			(clearance 0)
		)
		(min_thickness 0.25)
		(keepout
			(tracks not_allowed)
			(vias allowed)
			(pads allowed)
			(copperpour not_allowed)
			(footprints allowed)
		)
		(placement
			(enabled no)
			(sheetname "")
		)
		(fill
			(thermal_gap 0.5)
			(thermal_bridge_width 0.5)
			(island_removal_mode 0)
		)
		(polygon
			(pts
				(arc
					(start 159.977074 -403.502876)
					(mid 159.596074 -403.883876)
					(end 159.977074 -404.264876)
				)
				(arc
					(start 160.840674 -404.264876)
					(mid 161.221674 -403.883876)
					(end 160.840674 -403.502876)
				)
			)
		)
	)
	(zone
		(layers "F.Cu" "B.Cu" "In1.Cu" "In2.Cu" "In3.Cu" "In4.Cu" "In5.Cu" "In6.Cu"
			"In7.Cu" "In8.Cu" "In9.Cu" "In10.Cu" "In11.Cu" "In12.Cu" "In13.Cu" "In14.Cu"
			"In15.Cu" "In16.Cu"
		)
		(hatch none 0.5)
		(connect_pads
			(clearance 0)
		)
		(min_thickness 0.25)
		(keepout
			(tracks not_allowed)
			(vias allowed)
			(pads allowed)
			(copperpour not_allowed)
			(footprints allowed)
		)
		(placement
			(enabled no)
			(sheetname "")
		)
		(fill
			(thermal_gap 0.5)
			(thermal_bridge_width 0.5)
			(island_removal_mode 0)
		)
		(polygon
			(pts
				(arc
					(start 129.666492 -217.97645)
					(mid 129.686176 -217.92904)
					(end 129.692908 -217.878152)
				)
				(arc
					(start 129.692908 -217.878152)
					(mid 129.635252 -217.738958)
					(end 129.496058 -217.681302)
				)
				(arc
					(start 129.496058 -217.681302)
					(mid 129.397627 -217.707718)
					(end 129.325624 -217.779854)
				)
				(arc
					(start 128.855978 -218.593924)
					(mid 128.836294 -218.641334)
					(end 128.829562 -218.692222)
				)
				(arc
					(start 128.829562 -218.692222)
					(mid 128.887218 -218.831416)
					(end 129.026412 -218.889072)
				)
				(arc
					(start 129.026412 -218.889072)
					(mid 129.124843 -218.862656)
					(end 129.196846 -218.79052)
				)
			)
		)
	)
	(zone
		(layers "F.Cu" "B.Cu" "In1.Cu" "In2.Cu" "In3.Cu" "In4.Cu" "In5.Cu" "In6.Cu"
			"In7.Cu" "In8.Cu" "In9.Cu" "In10.Cu" "In11.Cu" "In12.Cu" "In13.Cu" "In14.Cu"
			"In15.Cu" "In16.Cu"
		)
		(hatch none 0.5)
		(connect_pads
			(clearance 0)
		)
		(min_thickness 0.25)
		(keepout
			(tracks not_allowed)
			(vias allowed)
			(pads allowed)
			(copperpour not_allowed)
			(footprints allowed)
		)
		(placement
			(enabled no)
			(sheetname "")
		)
		(fill
			(thermal_gap 0.5)
			(thermal_bridge_width 0.5)
			(island_removal_mode 0)
		)
		(polygon
			(pts
				(arc
					(start 430.048924 -4.57073)
					(mid 429.667924 -4.95173)
					(end 430.048924 -5.33273)
				)
				(arc
					(start 430.912524 -5.33273)
					(mid 431.293524 -4.95173)
					(end 430.912524 -4.57073)
				)
			)
		)
	)
	(zone
		(layers "F.Cu" "B.Cu" "In1.Cu" "In2.Cu" "In3.Cu" "In4.Cu" "In5.Cu" "In6.Cu"
			"In7.Cu" "In8.Cu" "In9.Cu" "In10.Cu" "In11.Cu" "In12.Cu" "In13.Cu" "In14.Cu"
			"In15.Cu" "In16.Cu"
		)
		(hatch none 0.5)
		(connect_pads
			(clearance 0)
		)
		(min_thickness 0.25)
		(keepout
			(tracks not_allowed)
			(vias allowed)
			(pads allowed)
			(copperpour not_allowed)
			(footprints allowed)
		)
		(placement
			(enabled no)
			(sheetname "")
		)
		(fill
			(thermal_gap 0.5)
			(thermal_bridge_width 0.5)
			(island_removal_mode 0)
		)
		(polygon
			(pts
				(arc
					(start 415.65449 -406.62352)
					(mid 415.27349 -407.00452)
					(end 415.65449 -407.38552)
				)
				(arc
					(start 416.51809 -407.38552)
					(mid 416.89909 -407.00452)
					(end 416.51809 -406.62352)
				)
			)
		)
	)
	(zone
		(layers "F.Cu" "B.Cu" "In1.Cu" "In2.Cu" "In3.Cu" "In4.Cu" "In5.Cu" "In6.Cu"
			"In7.Cu" "In8.Cu" "In9.Cu" "In10.Cu" "In11.Cu" "In12.Cu" "In13.Cu" "In14.Cu"
			"In15.Cu" "In16.Cu"
		)
		(hatch none 0.5)
		(connect_pads
			(clearance 0)
		)
		(min_thickness 0.25)
		(keepout
			(tracks not_allowed)
			(vias allowed)
			(pads allowed)
			(copperpour not_allowed)
			(footprints allowed)
		)
		(placement
			(enabled no)
			(sheetname "")
		)
		(fill
			(thermal_gap 0.5)
			(thermal_bridge_width 0.5)
			(island_removal_mode 0)
		)
		(polygon
			(pts
				(arc
					(start 351.531428 -285.563056)
					(mid 351.511744 -285.610466)
					(end 351.505012 -285.661354)
				)
				(arc
					(start 351.505012 -285.661354)
					(mid 351.562668 -285.800548)
					(end 351.701862 -285.858204)
				)
				(arc
					(start 351.701862 -285.858204)
					(mid 351.800293 -285.831788)
					(end 351.872296 -285.759652)
				)
				(arc
					(start 352.342196 -284.945582)
					(mid 352.36188 -284.898172)
					(end 352.368612 -284.847284)
				)
				(arc
					(start 352.368612 -284.847284)
					(mid 352.310956 -284.70809)
					(end 352.171762 -284.650434)
				)
				(arc
					(start 352.171762 -284.650434)
					(mid 352.073331 -284.67685)
					(end 352.001328 -284.748986)
				)
			)
		)
	)
	(zone
		(layers "F.Cu" "B.Cu" "In1.Cu" "In2.Cu" "In3.Cu" "In4.Cu" "In5.Cu" "In6.Cu"
			"In7.Cu" "In8.Cu" "In9.Cu" "In10.Cu" "In11.Cu" "In12.Cu" "In13.Cu" "In14.Cu"
			"In15.Cu" "In16.Cu"
		)
		(hatch none 0.5)
		(connect_pads
			(clearance 0)
		)
		(min_thickness 0.25)
		(keepout
			(tracks not_allowed)
			(vias allowed)
			(pads allowed)
			(copperpour not_allowed)
			(footprints allowed)
		)
		(placement
			(enabled no)
			(sheetname "")
		)
		(fill
			(thermal_gap 0.5)
			(thermal_bridge_width 0.5)
			(island_removal_mode 0)
		)
		(polygon
			(pts
				(arc
					(start 338.873846 -288.917126)
					(mid 338.215986 -288.917126)
					(end 338.873846 -288.917126)
				)
			)
		)
	)
	(zone
		(layers "F.Cu" "B.Cu" "In1.Cu" "In2.Cu" "In3.Cu" "In4.Cu" "In5.Cu" "In6.Cu"
			"In7.Cu" "In8.Cu" "In9.Cu" "In10.Cu" "In11.Cu" "In12.Cu" "In13.Cu" "In14.Cu"
			"In15.Cu" "In16.Cu"
		)
		(hatch none 0.5)
		(connect_pads
			(clearance 0)
		)
		(min_thickness 0.25)
		(keepout
			(tracks not_allowed)
			(vias allowed)
			(pads allowed)
			(copperpour not_allowed)
			(footprints allowed)
		)
		(placement
			(enabled no)
			(sheetname "")
		)
		(fill
			(thermal_gap 0.5)
			(thermal_bridge_width 0.5)
			(island_removal_mode 0)
		)
		(polygon
			(pts
				(arc
					(start 348.631764 -224.389442)
					(mid 347.973904 -224.389442)
					(end 348.631764 -224.389442)
				)
			)
		)
	)
	(zone
		(layers "F.Cu" "B.Cu" "In1.Cu" "In2.Cu" "In3.Cu" "In4.Cu" "In5.Cu" "In6.Cu"
			"In7.Cu" "In8.Cu" "In9.Cu" "In10.Cu" "In11.Cu" "In12.Cu" "In13.Cu" "In14.Cu"
			"In15.Cu" "In16.Cu"
		)
		(hatch none 0.5)
		(connect_pads
			(clearance 0)
		)
		(min_thickness 0.25)
		(keepout
			(tracks not_allowed)
			(vias allowed)
			(pads allowed)
			(copperpour not_allowed)
			(footprints allowed)
		)
		(placement
			(enabled no)
			(sheetname "")
		)
		(fill
			(thermal_gap 0.5)
			(thermal_bridge_width 0.5)
			(island_removal_mode 0)
		)
		(polygon
			(pts
				(arc
					(start 109.149896 -224.389442)
					(mid 108.492036 -224.389442)
					(end 109.149896 -224.389442)
				)
			)
		)
	)
	(zone
		(layers "F.Cu" "B.Cu" "In1.Cu" "In2.Cu" "In3.Cu" "In4.Cu" "In5.Cu" "In6.Cu"
			"In7.Cu" "In8.Cu" "In9.Cu" "In10.Cu" "In11.Cu" "In12.Cu" "In13.Cu" "In14.Cu"
			"In15.Cu" "In16.Cu"
		)
		(hatch none 0.5)
		(connect_pads
			(clearance 0)
		)
		(min_thickness 0.25)
		(keepout
			(tracks not_allowed)
			(vias allowed)
			(pads allowed)
			(copperpour not_allowed)
			(footprints allowed)
		)
		(placement
			(enabled no)
			(sheetname "")
		)
		(fill
			(thermal_gap 0.5)
			(thermal_bridge_width 0.5)
			(island_removal_mode 0)
		)
		(polygon
			(pts
				(arc
					(start 374.47601 -217.064336)
					(mid 373.81815 -217.064336)
					(end 374.47601 -217.064336)
				)
			)
		)
	)
	(zone
		(layers "F.Cu" "B.Cu" "In1.Cu" "In2.Cu" "In3.Cu" "In4.Cu" "In5.Cu" "In6.Cu"
			"In7.Cu" "In8.Cu" "In9.Cu" "In10.Cu" "In11.Cu" "In12.Cu" "In13.Cu" "In14.Cu"
			"In15.Cu" "In16.Cu"
		)
		(hatch none 0.5)
		(connect_pads
			(clearance 0)
		)
		(min_thickness 0.25)
		(keepout
			(tracks not_allowed)
			(vias allowed)
			(pads allowed)
			(copperpour not_allowed)
			(footprints allowed)
		)
		(placement
			(enabled no)
			(sheetname "")
		)
		(fill
			(thermal_gap 0.5)
			(thermal_bridge_width 0.5)
			(island_removal_mode 0)
		)
		(polygon
			(pts
				(arc
					(start 370.71681 -223.575626)
					(mid 370.05895 -223.575626)
					(end 370.71681 -223.575626)
				)
			)
		)
	)
	(zone
		(layers "F.Cu" "B.Cu" "In1.Cu" "In2.Cu" "In3.Cu" "In4.Cu" "In5.Cu" "In6.Cu"
			"In7.Cu" "In8.Cu" "In9.Cu" "In10.Cu" "In11.Cu" "In12.Cu" "In13.Cu" "In14.Cu"
			"In15.Cu" "In16.Cu"
		)
		(hatch none 0.5)
		(connect_pads
			(clearance 0)
		)
		(min_thickness 0.25)
		(keepout
			(tracks not_allowed)
			(vias allowed)
			(pads allowed)
			(copperpour not_allowed)
			(footprints allowed)
		)
		(placement
			(enabled no)
			(sheetname "")
		)
		(fill
			(thermal_gap 0.5)
			(thermal_bridge_width 0.5)
			(island_removal_mode 0)
		)
		(polygon
			(pts
				(arc
					(start 62.142116 -424.360594)
					(mid 62.164434 -424.414476)
					(end 62.218316 -424.436794)
				)
				(arc
					(start 63.158116 -424.436794)
					(mid 63.211998 -424.414476)
					(end 63.234316 -424.360594)
				)
				(arc
					(start 63.234316 -421.81907)
					(mid 63.211998 -421.765188)
					(end 63.158116 -421.74287)
				)
				(arc
					(start 62.218316 -421.74287)
					(mid 62.164434 -421.765188)
					(end 62.142116 -421.81907)
				)
			)
		)
	)
	(zone
		(layers "F.Cu" "B.Cu" "In1.Cu" "In2.Cu" "In3.Cu" "In4.Cu" "In5.Cu" "In6.Cu"
			"In7.Cu" "In8.Cu" "In9.Cu" "In10.Cu" "In11.Cu" "In12.Cu" "In13.Cu" "In14.Cu"
			"In15.Cu" "In16.Cu"
		)
		(hatch none 0.5)
		(connect_pads
			(clearance 0)
		)
		(min_thickness 0.25)
		(keepout
			(tracks not_allowed)
			(vias allowed)
			(pads allowed)
			(copperpour not_allowed)
			(footprints allowed)
		)
		(placement
			(enabled no)
			(sheetname "")
		)
		(fill
			(thermal_gap 0.5)
			(thermal_bridge_width 0.5)
			(island_removal_mode 0)
		)
		(polygon
			(pts
				(arc
					(start 101.942646 -217.162634)
					(mid 101.96233 -217.115224)
					(end 101.969062 -217.064336)
				)
				(arc
					(start 101.969062 -217.064336)
					(mid 101.911406 -216.925142)
					(end 101.772212 -216.867486)
				)
				(arc
					(start 101.772212 -216.867486)
					(mid 101.673781 -216.893902)
					(end 101.601778 -216.966038)
				)
				(arc
					(start 101.132132 -217.780108)
					(mid 101.112448 -217.827518)
					(end 101.105716 -217.878406)
				)
				(arc
					(start 101.105716 -217.878406)
					(mid 101.163372 -218.0176)
					(end 101.302566 -218.075256)
				)
				(arc
					(start 101.302566 -218.075256)
					(mid 101.400997 -218.04884)
					(end 101.473 -217.976704)
				)
			)
		)
	)
	(zone
		(layers "F.Cu" "B.Cu" "In1.Cu" "In2.Cu" "In3.Cu" "In4.Cu" "In5.Cu" "In6.Cu"
			"In7.Cu" "In8.Cu" "In9.Cu" "In10.Cu" "In11.Cu" "In12.Cu" "In13.Cu" "In14.Cu"
			"In15.Cu" "In16.Cu"
		)
		(hatch none 0.5)
		(connect_pads
			(clearance 0)
		)
		(min_thickness 0.25)
		(keepout
			(tracks not_allowed)
			(vias allowed)
			(pads allowed)
			(copperpour not_allowed)
			(footprints allowed)
		)
		(placement
			(enabled no)
			(sheetname "")
		)
		(fill
			(thermal_gap 0.5)
			(thermal_bridge_width 0.5)
			(island_removal_mode 0)
		)
		(polygon
			(pts
				(arc
					(start 106.281728 -281.493468)
					(mid 106.209739 -281.421309)
					(end 106.111294 -281.394916)
				)
				(arc
					(start 106.111294 -281.394916)
					(mid 105.9721 -281.452572)
					(end 105.914444 -281.591766)
				)
				(arc
					(start 105.914444 -281.591766)
					(mid 105.921201 -281.642647)
					(end 105.94086 -281.690064)
				)
				(arc
					(start 106.41076 -282.504134)
					(mid 106.482749 -282.576293)
					(end 106.581194 -282.602686)
				)
				(arc
					(start 106.581194 -282.602686)
					(mid 106.720388 -282.54503)
					(end 106.778044 -282.405836)
				)
				(arc
					(start 106.778044 -282.405836)
					(mid 106.771287 -282.354955)
					(end 106.751628 -282.307538)
				)
			)
		)
	)
	(zone
		(layers "F.Cu" "B.Cu" "In1.Cu" "In2.Cu" "In3.Cu" "In4.Cu" "In5.Cu" "In6.Cu"
			"In7.Cu" "In8.Cu" "In9.Cu" "In10.Cu" "In11.Cu" "In12.Cu" "In13.Cu" "In14.Cu"
			"In15.Cu" "In16.Cu"
		)
		(hatch none 0.5)
		(connect_pads
			(clearance 0)
		)
		(min_thickness 0.25)
		(keepout
			(tracks not_allowed)
			(vias allowed)
			(pads allowed)
			(copperpour not_allowed)
			(footprints allowed)
		)
		(placement
			(enabled no)
			(sheetname "")
		)
		(fill
			(thermal_gap 0.5)
			(thermal_bridge_width 0.5)
			(island_removal_mode 0)
		)
		(polygon
			(pts
				(arc
					(start 355.63175 -277.424134)
					(mid 355.559761 -277.351975)
					(end 355.461316 -277.325582)
				)
				(arc
					(start 355.461316 -277.325582)
					(mid 355.322122 -277.383238)
					(end 355.264466 -277.522432)
				)
				(arc
					(start 355.264466 -277.522432)
					(mid 355.271223 -277.573313)
					(end 355.290882 -277.62073)
				)
				(arc
					(start 355.760782 -278.4348)
					(mid 355.832771 -278.506959)
					(end 355.931216 -278.533352)
				)
				(arc
					(start 355.931216 -278.533352)
					(mid 356.07041 -278.475696)
					(end 356.128066 -278.336502)
				)
				(arc
					(start 356.128066 -278.336502)
					(mid 356.121309 -278.285621)
					(end 356.10165 -278.238204)
				)
			)
		)
	)
	(zone
		(layers "F.Cu" "B.Cu" "In1.Cu" "In2.Cu" "In3.Cu" "In4.Cu" "In5.Cu" "In6.Cu"
			"In7.Cu" "In8.Cu" "In9.Cu" "In10.Cu" "In11.Cu" "In12.Cu" "In13.Cu" "In14.Cu"
			"In15.Cu" "In16.Cu"
		)
		(hatch none 0.5)
		(connect_pads
			(clearance 0)
		)
		(min_thickness 0.25)
		(keepout
			(tracks not_allowed)
			(vias allowed)
			(pads allowed)
			(copperpour not_allowed)
			(footprints allowed)
		)
		(placement
			(enabled no)
			(sheetname "")
		)
		(fill
			(thermal_gap 0.5)
			(thermal_bridge_width 0.5)
			(island_removal_mode 0)
		)
		(polygon
			(pts
				(arc
					(start 376.935746 -288.103056)
					(mid 376.277886 -288.103056)
					(end 376.935746 -288.103056)
				)
			)
		)
	)
	(zone
		(layers "F.Cu" "B.Cu" "In1.Cu" "In2.Cu" "In3.Cu" "In4.Cu" "In5.Cu" "In6.Cu"
			"In7.Cu" "In8.Cu" "In9.Cu" "In10.Cu" "In11.Cu" "In12.Cu" "In13.Cu" "In14.Cu"
			"In15.Cu" "In16.Cu"
		)
		(hatch none 0.5)
		(connect_pads
			(clearance 0)
		)
		(min_thickness 0.25)
		(keepout
			(tracks not_allowed)
			(vias allowed)
			(pads allowed)
			(copperpour not_allowed)
			(footprints allowed)
		)
		(placement
			(enabled no)
			(sheetname "")
		)
		(fill
			(thermal_gap 0.5)
			(thermal_bridge_width 0.5)
			(island_removal_mode 0)
		)
		(polygon
			(pts
				(arc
					(start 344.40241 -217.064336)
					(mid 343.74455 -217.064336)
					(end 344.40241 -217.064336)
				)
			)
		)
	)
	(zone
		(layers "F.Cu" "B.Cu" "In1.Cu" "In2.Cu" "In3.Cu" "In4.Cu" "In5.Cu" "In6.Cu"
			"In7.Cu" "In8.Cu" "In9.Cu" "In10.Cu" "In11.Cu" "In12.Cu" "In13.Cu" "In14.Cu"
			"In15.Cu" "In16.Cu"
		)
		(hatch none 0.5)
		(connect_pads
			(clearance 0)
		)
		(min_thickness 0.25)
		(keepout
			(tracks not_allowed)
			(vias allowed)
			(pads allowed)
			(copperpour not_allowed)
			(footprints allowed)
		)
		(placement
			(enabled no)
			(sheetname "")
		)
		(fill
			(thermal_gap 0.5)
			(thermal_bridge_width 0.5)
			(island_removal_mode 0)
		)
		(polygon
			(pts
				(arc
					(start 133.754114 -406.62352)
					(mid 133.373114 -407.00452)
					(end 133.754114 -407.38552)
				)
				(arc
					(start 134.617714 -407.38552)
					(mid 134.998714 -407.00452)
					(end 134.617714 -406.62352)
				)
			)
		)
	)
	(zone
		(layers "F.Cu" "B.Cu" "In1.Cu" "In2.Cu" "In3.Cu" "In4.Cu" "In5.Cu" "In6.Cu"
			"In7.Cu" "In8.Cu" "In9.Cu" "In10.Cu" "In11.Cu" "In12.Cu" "In13.Cu" "In14.Cu"
			"In15.Cu" "In16.Cu"
		)
		(hatch none 0.5)
		(connect_pads
			(clearance 0)
		)
		(min_thickness 0.25)
		(keepout
			(tracks not_allowed)
			(vias allowed)
			(pads allowed)
			(copperpour not_allowed)
			(footprints allowed)
		)
		(placement
			(enabled no)
			(sheetname "")
		)
		(fill
			(thermal_gap 0.5)
			(thermal_bridge_width 0.5)
			(island_removal_mode 0)
		)
		(polygon
			(pts
				(arc
					(start 135.574278 -288.103056)
					(mid 134.916418 -288.103056)
					(end 135.574278 -288.103056)
				)
			)
		)
	)
	(zone
		(layers "F.Cu" "B.Cu" "In1.Cu" "In2.Cu" "In3.Cu" "In4.Cu" "In5.Cu" "In6.Cu"
			"In7.Cu" "In8.Cu" "In9.Cu" "In10.Cu" "In11.Cu" "In12.Cu" "In13.Cu" "In14.Cu"
			"In15.Cu" "In16.Cu"
		)
		(hatch none 0.5)
		(connect_pads
			(clearance 0)
		)
		(min_thickness 0.25)
		(keepout
			(tracks not_allowed)
			(vias allowed)
			(pads allowed)
			(copperpour not_allowed)
			(footprints allowed)
		)
		(placement
			(enabled no)
			(sheetname "")
		)
		(fill
			(thermal_gap 0.5)
			(thermal_bridge_width 0.5)
			(island_removal_mode 0)
		)
		(polygon
			(pts
				(arc
					(start 29.503878 -18.75536)
					(mid 29.122878 -19.13636)
					(end 29.503878 -19.51736)
				)
				(arc
					(start 30.367478 -19.51736)
					(mid 30.748478 -19.13636)
					(end 30.367478 -18.75536)
				)
			)
		)
	)
	(zone
		(layers "F.Cu" "B.Cu" "In1.Cu" "In2.Cu" "In3.Cu" "In4.Cu" "In5.Cu" "In6.Cu"
			"In7.Cu" "In8.Cu" "In9.Cu" "In10.Cu" "In11.Cu" "In12.Cu" "In13.Cu" "In14.Cu"
			"In15.Cu" "In16.Cu"
		)
		(hatch none 0.5)
		(connect_pads
			(clearance 0)
		)
		(min_thickness 0.25)
		(keepout
			(tracks not_allowed)
			(vias allowed)
			(pads allowed)
			(copperpour not_allowed)
			(footprints allowed)
		)
		(placement
			(enabled no)
			(sheetname "")
		)
		(fill
			(thermal_gap 0.5)
			(thermal_bridge_width 0.5)
			(island_removal_mode 0)
		)
		(polygon
			(pts
				(arc
					(start 341.52713 -288.831274)
					(mid 341.459422 -288.759423)
					(end 341.364316 -288.732976)
				)
				(arc
					(start 341.364316 -288.732976)
					(mid 341.234102 -288.786912)
					(end 341.180166 -288.917126)
				)
				(arc
					(start 341.180166 -288.917126)
					(mid 341.185617 -288.961347)
					(end 341.201502 -289.002978)
				)
				(arc
					(start 341.671148 -289.892994)
					(mid 341.738856 -289.964845)
					(end 341.833962 -289.991292)
				)
				(arc
					(start 341.833962 -289.991292)
					(mid 341.964176 -289.937356)
					(end 342.018112 -289.807142)
				)
				(arc
					(start 342.018112 -289.807142)
					(mid 342.012661 -289.762921)
					(end 341.996776 -289.72129)
				)
			)
		)
	)
	(zone
		(layers "F.Cu" "B.Cu" "In1.Cu" "In2.Cu" "In3.Cu" "In4.Cu" "In5.Cu" "In6.Cu"
			"In7.Cu" "In8.Cu" "In9.Cu" "In10.Cu" "In11.Cu" "In12.Cu" "In13.Cu" "In14.Cu"
			"In15.Cu" "In16.Cu"
		)
		(hatch none 0.5)
		(connect_pads
			(clearance 0)
		)
		(min_thickness 0.25)
		(keepout
			(tracks not_allowed)
			(vias allowed)
			(pads allowed)
			(copperpour not_allowed)
			(footprints allowed)
		)
		(placement
			(enabled no)
			(sheetname "")
		)
		(fill
			(thermal_gap 0.5)
			(thermal_bridge_width 0.5)
			(island_removal_mode 0)
		)
		(polygon
			(pts
				(arc
					(start 75.548998 -403.502876)
					(mid 75.167998 -403.883876)
					(end 75.548998 -404.264876)
				)
				(arc
					(start 76.412598 -404.264876)
					(mid 76.793598 -403.883876)
					(end 76.412598 -403.502876)
				)
			)
		)
	)
	(zone
		(layers "F.Cu" "B.Cu" "In1.Cu" "In2.Cu" "In3.Cu" "In4.Cu" "In5.Cu" "In6.Cu"
			"In7.Cu" "In8.Cu" "In9.Cu" "In10.Cu" "In11.Cu" "In12.Cu" "In13.Cu" "In14.Cu"
			"In15.Cu" "In16.Cu"
		)
		(hatch none 0.5)
		(connect_pads
			(clearance 0)
		)
		(min_thickness 0.25)
		(keepout
			(tracks not_allowed)
			(vias allowed)
			(pads allowed)
			(copperpour not_allowed)
			(footprints allowed)
		)
		(placement
			(enabled no)
			(sheetname "")
		)
		(fill
			(thermal_gap 0.5)
			(thermal_bridge_width 0.5)
			(island_removal_mode 0)
		)
		(polygon
			(pts
				(arc
					(start 351.921064 -213.732618)
					(mid 351.263204 -213.732618)
					(end 351.921064 -213.732618)
				)
			)
		)
	)
	(zone
		(layers "F.Cu" "B.Cu" "In1.Cu" "In2.Cu" "In3.Cu" "In4.Cu" "In5.Cu" "In6.Cu"
			"In7.Cu" "In8.Cu" "In9.Cu" "In10.Cu" "In11.Cu" "In12.Cu" "In13.Cu" "In14.Cu"
			"In15.Cu" "In16.Cu"
		)
		(hatch none 0.5)
		(connect_pads
			(clearance 0)
		)
		(min_thickness 0.25)
		(keepout
			(tracks not_allowed)
			(vias allowed)
			(pads allowed)
			(copperpour not_allowed)
			(footprints allowed)
		)
		(placement
			(enabled no)
			(sheetname "")
		)
		(fill
			(thermal_gap 0.5)
			(thermal_bridge_width 0.5)
			(island_removal_mode 0)
		)
		(polygon
			(pts
				(arc
					(start 104.2924 -224.291144)
					(mid 104.220411 -224.218985)
					(end 104.121966 -224.192592)
				)
				(arc
					(start 104.121966 -224.192592)
					(mid 103.982772 -224.250248)
					(end 103.925116 -224.389442)
				)
				(arc
					(start 103.925116 -224.389442)
					(mid 103.931873 -224.440323)
					(end 103.951532 -224.48774)
				)
				(arc
					(start 104.421178 -225.301556)
					(mid 104.493167 -225.373715)
					(end 104.591612 -225.400108)
				)
				(arc
					(start 104.591612 -225.400108)
					(mid 104.730806 -225.342452)
					(end 104.788462 -225.203258)
				)
				(arc
					(start 104.788462 -225.203258)
					(mid 104.781705 -225.152377)
					(end 104.762046 -225.10496)
				)
			)
		)
	)
	(zone
		(layers "F.Cu" "B.Cu" "In1.Cu" "In2.Cu" "In3.Cu" "In4.Cu" "In5.Cu" "In6.Cu"
			"In7.Cu" "In8.Cu" "In9.Cu" "In10.Cu" "In11.Cu" "In12.Cu" "In13.Cu" "In14.Cu"
			"In15.Cu" "In16.Cu"
		)
		(hatch none 0.5)
		(connect_pads
			(clearance 0)
		)
		(min_thickness 0.25)
		(keepout
			(tracks not_allowed)
			(vias allowed)
			(pads allowed)
			(copperpour not_allowed)
			(footprints allowed)
		)
		(placement
			(enabled no)
			(sheetname "")
		)
		(fill
			(thermal_gap 0.5)
			(thermal_bridge_width 0.5)
			(island_removal_mode 0)
		)
		(polygon
			(pts
				(arc
					(start 76.895198 -406.62352)
					(mid 76.514198 -407.00452)
					(end 76.895198 -407.38552)
				)
				(arc
					(start 77.758798 -407.38552)
					(mid 78.139798 -407.00452)
					(end 77.758798 -406.62352)
				)
			)
		)
	)
	(zone
		(layers "F.Cu" "B.Cu" "In1.Cu" "In2.Cu" "In3.Cu" "In4.Cu" "In5.Cu" "In6.Cu"
			"In7.Cu" "In8.Cu" "In9.Cu" "In10.Cu" "In11.Cu" "In12.Cu" "In13.Cu" "In14.Cu"
			"In15.Cu" "In16.Cu"
		)
		(hatch none 0.5)
		(connect_pads
			(clearance 0)
		)
		(min_thickness 0.25)
		(keepout
			(tracks not_allowed)
			(vias allowed)
			(pads allowed)
			(copperpour not_allowed)
			(footprints allowed)
		)
		(placement
			(enabled no)
			(sheetname "")
		)
		(fill
			(thermal_gap 0.5)
			(thermal_bridge_width 0.5)
			(island_removal_mode 0)
		)
		(polygon
			(pts
				(arc
					(start 120.268492 -217.97645)
					(mid 120.288176 -217.92904)
					(end 120.294908 -217.878152)
				)
				(arc
					(start 120.294908 -217.878152)
					(mid 120.237252 -217.738958)
					(end 120.098058 -217.681302)
				)
				(arc
					(start 120.098058 -217.681302)
					(mid 119.999627 -217.707718)
					(end 119.927624 -217.779854)
				)
				(arc
					(start 119.457978 -218.593924)
					(mid 119.438294 -218.641334)
					(end 119.431562 -218.692222)
				)
				(arc
					(start 119.431562 -218.692222)
					(mid 119.489218 -218.831416)
					(end 119.628412 -218.889072)
				)
				(arc
					(start 119.628412 -218.889072)
					(mid 119.726843 -218.862656)
					(end 119.798846 -218.79052)
				)
			)
		)
	)
	(zone
		(layers "F.Cu" "B.Cu" "In1.Cu" "In2.Cu" "In3.Cu" "In4.Cu" "In5.Cu" "In6.Cu"
			"In7.Cu" "In8.Cu" "In9.Cu" "In10.Cu" "In11.Cu" "In12.Cu" "In13.Cu" "In14.Cu"
			"In15.Cu" "In16.Cu"
		)
		(hatch none 0.5)
		(connect_pads
			(clearance 0)
		)
		(min_thickness 0.25)
		(keepout
			(tracks not_allowed)
			(vias allowed)
			(pads allowed)
			(copperpour not_allowed)
			(footprints allowed)
		)
		(placement
			(enabled no)
			(sheetname "")
		)
		(fill
			(thermal_gap 0.5)
			(thermal_bridge_width 0.5)
			(island_removal_mode 0)
		)
		(polygon
			(pts
				(arc
					(start 380.61265 -403.502876)
					(mid 380.23165 -403.883876)
					(end 380.61265 -404.264876)
				)
				(arc
					(start 381.47625 -404.264876)
					(mid 381.85725 -403.883876)
					(end 381.47625 -403.502876)
				)
			)
		)
	)
	(zone
		(layers "F.Cu" "B.Cu" "In1.Cu" "In2.Cu" "In3.Cu" "In4.Cu" "In5.Cu" "In6.Cu"
			"In7.Cu" "In8.Cu" "In9.Cu" "In10.Cu" "In11.Cu" "In12.Cu" "In13.Cu" "In14.Cu"
			"In15.Cu" "In16.Cu"
		)
		(hatch none 0.5)
		(connect_pads
			(clearance 0)
		)
		(min_thickness 0.25)
		(keepout
			(tracks not_allowed)
			(vias allowed)
			(pads allowed)
			(copperpour not_allowed)
			(footprints allowed)
		)
		(placement
			(enabled no)
			(sheetname "")
		)
		(fill
			(thermal_gap 0.5)
			(thermal_bridge_width 0.5)
			(island_removal_mode 0)
		)
		(polygon
			(pts
				(arc
					(start 105.69448 -213.646766)
					(mid 105.626772 -213.574915)
					(end 105.531666 -213.548468)
				)
				(arc
					(start 105.531666 -213.548468)
					(mid 105.401452 -213.602404)
					(end 105.347516 -213.732618)
				)
				(arc
					(start 105.347516 -213.732618)
					(mid 105.352967 -213.776839)
					(end 105.368852 -213.81847)
				)
				(arc
					(start 105.838244 -214.708486)
					(mid 105.905952 -214.780337)
					(end 106.001058 -214.806784)
				)
				(arc
					(start 106.001058 -214.806784)
					(mid 106.131272 -214.752848)
					(end 106.185208 -214.622634)
				)
				(arc
					(start 106.185208 -214.622634)
					(mid 106.179757 -214.578413)
					(end 106.163872 -214.536782)
				)
			)
		)
	)
	(zone
		(layers "F.Cu" "B.Cu" "In1.Cu" "In2.Cu" "In3.Cu" "In4.Cu" "In5.Cu" "In6.Cu"
			"In7.Cu" "In8.Cu" "In9.Cu" "In10.Cu" "In11.Cu" "In12.Cu" "In13.Cu" "In14.Cu"
			"In15.Cu" "In16.Cu"
		)
		(hatch none 0.5)
		(connect_pads
			(clearance 0)
		)
		(min_thickness 0.25)
		(keepout
			(tracks not_allowed)
			(vias allowed)
			(pads allowed)
			(copperpour not_allowed)
			(footprints allowed)
		)
		(placement
			(enabled no)
			(sheetname "")
		)
		(fill
			(thermal_gap 0.5)
			(thermal_bridge_width 0.5)
			(island_removal_mode 0)
		)
		(polygon
			(pts
				(arc
					(start 103.432864 -277.522432)
					(mid 104.090724 -277.522432)
					(end 103.432864 -277.522432)
				)
			)
		)
	)
	(zone
		(layers "F.Cu" "B.Cu" "In1.Cu" "In2.Cu" "In3.Cu" "In4.Cu" "In5.Cu" "In6.Cu"
			"In7.Cu" "In8.Cu" "In9.Cu" "In10.Cu" "In11.Cu" "In12.Cu" "In13.Cu" "In14.Cu"
			"In15.Cu" "In16.Cu"
		)
		(hatch none 0.5)
		(connect_pads
			(clearance 0)
		)
		(min_thickness 0.25)
		(keepout
			(tracks not_allowed)
			(vias allowed)
			(pads allowed)
			(copperpour not_allowed)
			(footprints allowed)
		)
		(placement
			(enabled no)
			(sheetname "")
		)
		(fill
			(thermal_gap 0.5)
			(thermal_bridge_width 0.5)
			(island_removal_mode 0)
		)
		(polygon
			(pts
				(arc
					(start 338.293964 -217.878406)
					(mid 337.636104 -217.878406)
					(end 338.293964 -217.878406)
				)
			)
		)
	)
	(zone
		(layers "F.Cu" "B.Cu" "In1.Cu" "In2.Cu" "In3.Cu" "In4.Cu" "In5.Cu" "In6.Cu"
			"In7.Cu" "In8.Cu" "In9.Cu" "In10.Cu" "In11.Cu" "In12.Cu" "In13.Cu" "In14.Cu"
			"In15.Cu" "In16.Cu"
		)
		(hatch none 0.5)
		(connect_pads
			(clearance 0)
		)
		(min_thickness 0.25)
		(keepout
			(tracks not_allowed)
			(vias allowed)
			(pads allowed)
			(copperpour not_allowed)
			(footprints allowed)
		)
		(placement
			(enabled no)
			(sheetname "")
		)
		(fill
			(thermal_gap 0.5)
			(thermal_bridge_width 0.5)
			(island_removal_mode 0)
		)
		(polygon
			(pts
				(arc
					(start 340.753192 -285.661354)
					(mid 340.095332 -285.661354)
					(end 340.753192 -285.661354)
				)
			)
		)
	)
	(zone
		(layers "F.Cu" "B.Cu" "In1.Cu" "In2.Cu" "In3.Cu" "In4.Cu" "In5.Cu" "In6.Cu"
			"In7.Cu" "In8.Cu" "In9.Cu" "In10.Cu" "In11.Cu" "In12.Cu" "In13.Cu" "In14.Cu"
			"In15.Cu" "In16.Cu"
		)
		(hatch none 0.5)
		(connect_pads
			(clearance 0)
		)
		(min_thickness 0.25)
		(keepout
			(tracks not_allowed)
			(vias allowed)
			(pads allowed)
			(copperpour not_allowed)
			(footprints allowed)
		)
		(placement
			(enabled no)
			(sheetname "")
		)
		(fill
			(thermal_gap 0.5)
			(thermal_bridge_width 0.5)
			(island_removal_mode 0)
		)
		(polygon
			(pts
				(arc
					(start 26.835354 -400.813016)
					(mid 27.216354 -400.432016)
					(end 26.835354 -400.051016)
				)
				(arc
					(start 25.971754 -400.051016)
					(mid 25.590754 -400.432016)
					(end 25.971754 -400.813016)
				)
			)
		)
	)
	(zone
		(layers "F.Cu" "B.Cu" "In1.Cu" "In2.Cu" "In3.Cu" "In4.Cu" "In5.Cu" "In6.Cu"
			"In7.Cu" "In8.Cu" "In9.Cu" "In10.Cu" "In11.Cu" "In12.Cu" "In13.Cu" "In14.Cu"
			"In15.Cu" "In16.Cu"
		)
		(hatch none 0.5)
		(connect_pads
			(clearance 0)
		)
		(min_thickness 0.25)
		(keepout
			(tracks not_allowed)
			(vias allowed)
			(pads allowed)
			(copperpour not_allowed)
			(footprints allowed)
		)
		(placement
			(enabled no)
			(sheetname "")
		)
		(fill
			(thermal_gap 0.5)
			(thermal_bridge_width 0.5)
			(island_removal_mode 0)
		)
		(polygon
			(pts
				(arc
					(start 58.142124 -424.360594)
					(mid 58.164442 -424.414476)
					(end 58.218324 -424.436794)
				)
				(arc
					(start 59.158124 -424.436794)
					(mid 59.212006 -424.414476)
					(end 59.234324 -424.360594)
				)
				(arc
					(start 59.234324 -421.81907)
					(mid 59.212006 -421.765188)
					(end 59.158124 -421.74287)
				)
				(arc
					(start 58.218324 -421.74287)
					(mid 58.164442 -421.765188)
					(end 58.142124 -421.81907)
				)
			)
		)
	)
	(zone
		(layers "F.Cu" "B.Cu" "In1.Cu" "In2.Cu" "In3.Cu" "In4.Cu" "In5.Cu" "In6.Cu"
			"In7.Cu" "In8.Cu" "In9.Cu" "In10.Cu" "In11.Cu" "In12.Cu" "In13.Cu" "In14.Cu"
			"In15.Cu" "In16.Cu"
		)
		(hatch none 0.5)
		(connect_pads
			(clearance 0)
		)
		(min_thickness 0.25)
		(keepout
			(tracks not_allowed)
			(vias allowed)
			(pads allowed)
			(copperpour not_allowed)
			(footprints allowed)
		)
		(placement
			(enabled no)
			(sheetname "")
		)
		(fill
			(thermal_gap 0.5)
			(thermal_bridge_width 0.5)
			(island_removal_mode 0)
		)
		(polygon
			(pts
				(arc
					(start 369.614704 -176.019968)
					(mid 369.763494 -176.379178)
					(end 370.122704 -176.527968)
				)
				(arc
					(start 370.123212 -176.527968)
					(mid 370.254421 -176.510731)
					(end 370.376704 -176.46015)
				)
				(arc
					(start 371.300756 -175.926496)
					(mid 371.486689 -175.74056)
					(end 371.554756 -175.486568)
				)
				(arc
					(start 371.554756 -175.486568)
					(mid 371.405966 -175.127358)
					(end 371.046756 -174.978568)
				)
				(arc
					(start 371.046248 -174.978568)
					(mid 370.915039 -174.995805)
					(end 370.792756 -175.046386)
				)
				(arc
					(start 369.868704 -175.58004)
					(mid 369.682771 -175.765976)
					(end 369.614704 -176.019968)
				)
			)
		)
	)
	(zone
		(layers "F.Cu" "B.Cu" "In1.Cu" "In2.Cu" "In3.Cu" "In4.Cu" "In5.Cu" "In6.Cu"
			"In7.Cu" "In8.Cu" "In9.Cu" "In10.Cu" "In11.Cu" "In12.Cu" "In13.Cu" "In14.Cu"
			"In15.Cu" "In16.Cu"
		)
		(hatch none 0.5)
		(connect_pads
			(clearance 0)
		)
		(min_thickness 0.25)
		(keepout
			(tracks not_allowed)
			(vias allowed)
			(pads allowed)
			(copperpour not_allowed)
			(footprints allowed)
		)
		(placement
			(enabled no)
			(sheetname "")
		)
		(fill
			(thermal_gap 0.5)
			(thermal_bridge_width 0.5)
			(island_removal_mode 0)
		)
		(polygon
			(pts
				(arc
					(start 406.128982 -4.57073)
					(mid 405.747982 -4.95173)
					(end 406.128982 -5.33273)
				)
				(arc
					(start 406.992582 -5.33273)
					(mid 407.373582 -4.95173)
					(end 406.992582 -4.57073)
				)
			)
		)
	)
	(zone
		(layers "F.Cu" "B.Cu" "In1.Cu" "In2.Cu" "In3.Cu" "In4.Cu" "In5.Cu" "In6.Cu"
			"In7.Cu" "In8.Cu" "In9.Cu" "In10.Cu" "In11.Cu" "In12.Cu" "In13.Cu" "In14.Cu"
			"In15.Cu" "In16.Cu"
		)
		(hatch none 0.5)
		(connect_pads
			(clearance 0)
		)
		(min_thickness 0.25)
		(keepout
			(tracks not_allowed)
			(vias allowed)
			(pads allowed)
			(copperpour not_allowed)
			(footprints allowed)
		)
		(placement
			(enabled no)
			(sheetname "")
		)
		(fill
			(thermal_gap 0.5)
			(thermal_bridge_width 0.5)
			(island_removal_mode 0)
		)
		(polygon
			(pts
				(arc
					(start 147.724114 -400.477228)
					(mid 147.343114 -400.858228)
					(end 147.724114 -401.239228)
				)
				(arc
					(start 148.587714 -401.239228)
					(mid 148.968714 -400.858228)
					(end 148.587714 -400.477228)
				)
			)
		)
	)
	(zone
		(layers "F.Cu" "B.Cu" "In1.Cu" "In2.Cu" "In3.Cu" "In4.Cu" "In5.Cu" "In6.Cu"
			"In7.Cu" "In8.Cu" "In9.Cu" "In10.Cu" "In11.Cu" "In12.Cu" "In13.Cu" "In14.Cu"
			"In15.Cu" "In16.Cu"
		)
		(hatch none 0.5)
		(connect_pads
			(clearance 0)
		)
		(min_thickness 0.25)
		(keepout
			(tracks not_allowed)
			(vias allowed)
			(pads allowed)
			(copperpour not_allowed)
			(footprints allowed)
		)
		(placement
			(enabled no)
			(sheetname "")
		)
		(fill
			(thermal_gap 0.5)
			(thermal_bridge_width 0.5)
			(island_removal_mode 0)
		)
		(polygon
			(pts
				(xy 706.622158 -391.095738) (xy 711.622148 -391.095738) (xy 711.317348 -391.400538) (xy 706.926958 -391.400538)
			)
		)
	)
	(zone
		(layers "F.Cu" "B.Cu" "In1.Cu" "In2.Cu" "In3.Cu" "In4.Cu" "In5.Cu" "In6.Cu"
			"In7.Cu" "In8.Cu" "In9.Cu" "In10.Cu" "In11.Cu" "In12.Cu" "In13.Cu" "In14.Cu"
			"In15.Cu" "In16.Cu"
		)
		(hatch none 0.5)
		(connect_pads
			(clearance 0)
		)
		(min_thickness 0.25)
		(keepout
			(tracks not_allowed)
			(vias allowed)
			(pads allowed)
			(copperpour not_allowed)
			(footprints allowed)
		)
		(placement
			(enabled no)
			(sheetname "")
		)
		(fill
			(thermal_gap 0.5)
			(thermal_bridge_width 0.5)
			(island_removal_mode 0)
		)
		(polygon
			(pts
				(arc
					(start 109.071664 -277.522432)
					(mid 109.729524 -277.522432)
					(end 109.071664 -277.522432)
				)
			)
		)
	)
	(zone
		(layers "F.Cu" "B.Cu" "In1.Cu" "In2.Cu" "In3.Cu" "In4.Cu" "In5.Cu" "In6.Cu"
			"In7.Cu" "In8.Cu" "In9.Cu" "In10.Cu" "In11.Cu" "In12.Cu" "In13.Cu" "In14.Cu"
			"In15.Cu" "In16.Cu"
		)
		(hatch none 0.5)
		(connect_pads
			(clearance 0)
		)
		(min_thickness 0.25)
		(keepout
			(tracks not_allowed)
			(vias allowed)
			(pads allowed)
			(copperpour not_allowed)
			(footprints allowed)
		)
		(placement
			(enabled no)
			(sheetname "")
		)
		(fill
			(thermal_gap 0.5)
			(thermal_bridge_width 0.5)
			(island_removal_mode 0)
		)
		(polygon
			(pts
				(arc
					(start 87.644224 -284.847538)
					(mid 86.986364 -284.847538)
					(end 87.644224 -284.847538)
				)
			)
		)
	)
	(zone
		(layers "F.Cu" "B.Cu" "In1.Cu" "In2.Cu" "In3.Cu" "In4.Cu" "In5.Cu" "In6.Cu"
			"In7.Cu" "In8.Cu" "In9.Cu" "In10.Cu" "In11.Cu" "In12.Cu" "In13.Cu" "In14.Cu"
			"In15.Cu" "In16.Cu"
		)
		(hatch none 0.5)
		(connect_pads
			(clearance 0)
		)
		(min_thickness 0.25)
		(keepout
			(tracks not_allowed)
			(vias allowed)
			(pads allowed)
			(copperpour not_allowed)
			(footprints allowed)
		)
		(placement
			(enabled no)
			(sheetname "")
		)
		(fill
			(thermal_gap 0.5)
			(thermal_bridge_width 0.5)
			(island_removal_mode 0)
		)
		(polygon
			(pts
				(arc
					(start 92.544646 -217.162634)
					(mid 92.56433 -217.115224)
					(end 92.571062 -217.064336)
				)
				(arc
					(start 92.571062 -217.064336)
					(mid 92.513406 -216.925142)
					(end 92.374212 -216.867486)
				)
				(arc
					(start 92.374212 -216.867486)
					(mid 92.275781 -216.893902)
					(end 92.203778 -216.966038)
				)
				(arc
					(start 91.734132 -217.780108)
					(mid 91.714448 -217.827518)
					(end 91.707716 -217.878406)
				)
				(arc
					(start 91.707716 -217.878406)
					(mid 91.765372 -218.0176)
					(end 91.904566 -218.075256)
				)
				(arc
					(start 91.904566 -218.075256)
					(mid 92.002997 -218.04884)
					(end 92.075 -217.976704)
				)
			)
		)
	)
	(zone
		(layers "F.Cu" "B.Cu" "In1.Cu" "In2.Cu" "In3.Cu" "In4.Cu" "In5.Cu" "In6.Cu"
			"In7.Cu" "In8.Cu" "In9.Cu" "In10.Cu" "In11.Cu" "In12.Cu" "In13.Cu" "In14.Cu"
			"In15.Cu" "In16.Cu"
		)
		(hatch none 0.5)
		(connect_pads
			(clearance 0)
		)
		(min_thickness 0.25)
		(keepout
			(tracks not_allowed)
			(vias allowed)
			(pads allowed)
			(copperpour not_allowed)
			(footprints allowed)
		)
		(placement
			(enabled no)
			(sheetname "")
		)
		(fill
			(thermal_gap 0.5)
			(thermal_bridge_width 0.5)
			(island_removal_mode 0)
		)
		(polygon
			(pts
				(arc
					(start 96.462596 -213.732618)
					(mid 95.804736 -213.732618)
					(end 96.462596 -213.732618)
				)
			)
		)
	)
	(zone
		(layers "F.Cu" "B.Cu" "In1.Cu" "In2.Cu" "In3.Cu" "In4.Cu" "In5.Cu" "In6.Cu"
			"In7.Cu" "In8.Cu" "In9.Cu" "In10.Cu" "In11.Cu" "In12.Cu" "In13.Cu" "In14.Cu"
			"In15.Cu" "In16.Cu"
		)
		(hatch none 0.5)
		(connect_pads
			(clearance 0)
		)
		(min_thickness 0.25)
		(keepout
			(tracks not_allowed)
			(vias allowed)
			(pads allowed)
			(copperpour not_allowed)
			(footprints allowed)
		)
		(placement
			(enabled no)
			(sheetname "")
		)
		(fill
			(thermal_gap 0.5)
			(thermal_bridge_width 0.5)
			(island_removal_mode 0)
		)
		(polygon
			(pts
				(arc
					(start 118.388892 -217.97645)
					(mid 118.408576 -217.92904)
					(end 118.415308 -217.878152)
				)
				(arc
					(start 118.415308 -217.878152)
					(mid 118.357652 -217.738958)
					(end 118.218458 -217.681302)
				)
				(arc
					(start 118.218458 -217.681302)
					(mid 118.120027 -217.707718)
					(end 118.048024 -217.779854)
				)
				(arc
					(start 117.578378 -218.593924)
					(mid 117.558694 -218.641334)
					(end 117.551962 -218.692222)
				)
				(arc
					(start 117.551962 -218.692222)
					(mid 117.609618 -218.831416)
					(end 117.748812 -218.889072)
				)
				(arc
					(start 117.748812 -218.889072)
					(mid 117.847243 -218.862656)
					(end 117.919246 -218.79052)
				)
			)
		)
	)
	(zone
		(layers "F.Cu" "B.Cu" "In1.Cu" "In2.Cu" "In3.Cu" "In4.Cu" "In5.Cu" "In6.Cu"
			"In7.Cu" "In8.Cu" "In9.Cu" "In10.Cu" "In11.Cu" "In12.Cu" "In13.Cu" "In14.Cu"
			"In15.Cu" "In16.Cu"
		)
		(hatch none 0.5)
		(connect_pads
			(clearance 0)
		)
		(min_thickness 0.25)
		(keepout
			(tracks not_allowed)
			(vias allowed)
			(pads allowed)
			(copperpour not_allowed)
			(footprints allowed)
		)
		(placement
			(enabled no)
			(sheetname "")
		)
		(fill
			(thermal_gap 0.5)
			(thermal_bridge_width 0.5)
			(island_removal_mode 0)
		)
		(polygon
			(pts
				(arc
					(start 361.46994 -46.421802)
					(mid 361.08894 -46.802802)
					(end 361.46994 -47.183802)
				)
				(arc
					(start 362.33354 -47.183802)
					(mid 362.71454 -46.802802)
					(end 362.33354 -46.421802)
				)
			)
		)
	)
	(zone
		(layers "F.Cu" "B.Cu" "In1.Cu" "In2.Cu" "In3.Cu" "In4.Cu" "In5.Cu" "In6.Cu"
			"In7.Cu" "In8.Cu" "In9.Cu" "In10.Cu" "In11.Cu" "In12.Cu" "In13.Cu" "In14.Cu"
			"In15.Cu" "In16.Cu"
		)
		(hatch none 0.5)
		(connect_pads
			(clearance 0)
		)
		(min_thickness 0.25)
		(keepout
			(tracks not_allowed)
			(vias allowed)
			(pads allowed)
			(copperpour not_allowed)
			(footprints allowed)
		)
		(placement
			(enabled no)
			(sheetname "")
		)
		(fill
			(thermal_gap 0.5)
			(thermal_bridge_width 0.5)
			(island_removal_mode 0)
		)
		(polygon
			(pts
				(arc
					(start 109.461046 -223.67367)
					(mid 109.48073 -223.62626)
					(end 109.487462 -223.575372)
				)
				(arc
					(start 109.487462 -223.575372)
					(mid 109.429806 -223.436178)
					(end 109.290612 -223.378522)
				)
				(arc
					(start 109.290612 -223.378522)
					(mid 109.192181 -223.404938)
					(end 109.120178 -223.477074)
				)
				(arc
					(start 108.650532 -224.291144)
					(mid 108.630848 -224.338554)
					(end 108.624116 -224.389442)
				)
				(arc
					(start 108.624116 -224.389442)
					(mid 108.681772 -224.528636)
					(end 108.820966 -224.586292)
				)
				(arc
					(start 108.820966 -224.586292)
					(mid 108.919397 -224.559876)
					(end 108.9914 -224.48774)
				)
			)
		)
	)
	(zone
		(layers "F.Cu" "B.Cu" "In1.Cu" "In2.Cu" "In3.Cu" "In4.Cu" "In5.Cu" "In6.Cu"
			"In7.Cu" "In8.Cu" "In9.Cu" "In10.Cu" "In11.Cu" "In12.Cu" "In13.Cu" "In14.Cu"
			"In15.Cu" "In16.Cu"
		)
		(hatch none 0.5)
		(connect_pads
			(clearance 0)
		)
		(min_thickness 0.25)
		(keepout
			(tracks not_allowed)
			(vias allowed)
			(pads allowed)
			(copperpour not_allowed)
			(footprints allowed)
		)
		(placement
			(enabled no)
			(sheetname "")
		)
		(fill
			(thermal_gap 0.5)
			(thermal_bridge_width 0.5)
			(island_removal_mode 0)
		)
		(polygon
			(pts
				(arc
					(start 100.221542 -223.575626)
					(mid 99.563682 -223.575626)
					(end 100.221542 -223.575626)
				)
			)
		)
	)
	(zone
		(layers "F.Cu" "B.Cu" "In1.Cu" "In2.Cu" "In3.Cu" "In4.Cu" "In5.Cu" "In6.Cu"
			"In7.Cu" "In8.Cu" "In9.Cu" "In10.Cu" "In11.Cu" "In12.Cu" "In13.Cu" "In14.Cu"
			"In15.Cu" "In16.Cu"
		)
		(hatch none 0.5)
		(connect_pads
			(clearance 0)
		)
		(min_thickness 0.25)
		(keepout
			(tracks not_allowed)
			(vias allowed)
			(pads allowed)
			(copperpour not_allowed)
			(footprints allowed)
		)
		(placement
			(enabled no)
			(sheetname "")
		)
		(fill
			(thermal_gap 0.5)
			(thermal_bridge_width 0.5)
			(island_removal_mode 0)
		)
		(polygon
			(pts
				(arc
					(start 97.402142 -225.203258)
					(mid 96.744282 -225.203258)
					(end 97.402142 -225.203258)
				)
			)
		)
	)
	(zone
		(layers "F.Cu" "B.Cu" "In1.Cu" "In2.Cu" "In3.Cu" "In4.Cu" "In5.Cu" "In6.Cu"
			"In7.Cu" "In8.Cu" "In9.Cu" "In10.Cu" "In11.Cu" "In12.Cu" "In13.Cu" "In14.Cu"
			"In15.Cu" "In16.Cu"
		)
		(hatch none 0.5)
		(connect_pads
			(clearance 0)
		)
		(min_thickness 0.25)
		(keepout
			(tracks not_allowed)
			(vias allowed)
			(pads allowed)
			(copperpour not_allowed)
			(footprints allowed)
		)
		(placement
			(enabled no)
			(sheetname "")
		)
		(fill
			(thermal_gap 0.5)
			(thermal_bridge_width 0.5)
			(island_removal_mode 0)
		)
		(polygon
			(pts
				(arc
					(start 134.336282 -215.436704)
					(mid 134.994142 -215.436704)
					(end 134.336282 -215.436704)
				)
			)
		)
	)
	(zone
		(layers "F.Cu" "B.Cu" "In1.Cu" "In2.Cu" "In3.Cu" "In4.Cu" "In5.Cu" "In6.Cu"
			"In7.Cu" "In8.Cu" "In9.Cu" "In10.Cu" "In11.Cu" "In12.Cu" "In13.Cu" "In14.Cu"
			"In15.Cu" "In16.Cu"
		)
		(hatch none 0.5)
		(connect_pads
			(clearance 0)
		)
		(min_thickness 0.25)
		(keepout
			(tracks not_allowed)
			(vias allowed)
			(pads allowed)
			(copperpour not_allowed)
			(footprints allowed)
		)
		(placement
			(enabled no)
			(sheetname "")
		)
		(fill
			(thermal_gap 0.5)
			(thermal_bridge_width 0.5)
			(island_removal_mode 0)
		)
		(polygon
			(pts
				(arc
					(start 118.85168 -213.646766)
					(mid 118.783972 -213.574915)
					(end 118.688866 -213.548468)
				)
				(arc
					(start 118.688866 -213.548468)
					(mid 118.558652 -213.602404)
					(end 118.504716 -213.732618)
				)
				(arc
					(start 118.504716 -213.732618)
					(mid 118.510167 -213.776839)
					(end 118.526052 -213.81847)
				)
				(arc
					(start 118.995444 -214.708486)
					(mid 119.063152 -214.780337)
					(end 119.158258 -214.806784)
				)
				(arc
					(start 119.158258 -214.806784)
					(mid 119.288472 -214.752848)
					(end 119.342408 -214.622634)
				)
				(arc
					(start 119.342408 -214.622634)
					(mid 119.336957 -214.578413)
					(end 119.321072 -214.536782)
				)
			)
		)
	)
	(zone
		(layers "F.Cu" "B.Cu" "In1.Cu" "In2.Cu" "In3.Cu" "In4.Cu" "In5.Cu" "In6.Cu"
			"In7.Cu" "In8.Cu" "In9.Cu" "In10.Cu" "In11.Cu" "In12.Cu" "In13.Cu" "In14.Cu"
			"In15.Cu" "In16.Cu"
		)
		(hatch none 0.5)
		(connect_pads
			(clearance 0)
		)
		(min_thickness 0.25)
		(keepout
			(tracks not_allowed)
			(vias allowed)
			(pads allowed)
			(copperpour not_allowed)
			(footprints allowed)
		)
		(placement
			(enabled no)
			(sheetname "")
		)
		(fill
			(thermal_gap 0.5)
			(thermal_bridge_width 0.5)
			(island_removal_mode 0)
		)
		(polygon
			(pts
				(arc
					(start 102.571296 -217.878406)
					(mid 101.913436 -217.878406)
					(end 102.571296 -217.878406)
				)
			)
		)
	)
	(zone
		(layers "F.Cu" "B.Cu" "In1.Cu" "In2.Cu" "In3.Cu" "In4.Cu" "In5.Cu" "In6.Cu"
			"In7.Cu" "In8.Cu" "In9.Cu" "In10.Cu" "In11.Cu" "In12.Cu" "In13.Cu" "In14.Cu"
			"In15.Cu" "In16.Cu"
		)
		(hatch none 0.5)
		(connect_pads
			(clearance 0)
		)
		(min_thickness 0.25)
		(keepout
			(tracks not_allowed)
			(vias allowed)
			(pads allowed)
			(copperpour not_allowed)
			(footprints allowed)
		)
		(placement
			(enabled no)
			(sheetname "")
		)
		(fill
			(thermal_gap 0.5)
			(thermal_bridge_width 0.5)
			(island_removal_mode 0)
		)
		(polygon
			(pts
				(arc
					(start 362.728764 -221.133924)
					(mid 362.070904 -221.133924)
					(end 362.728764 -221.133924)
				)
			)
		)
	)
	(zone
		(layers "F.Cu" "B.Cu" "In1.Cu" "In2.Cu" "In3.Cu" "In4.Cu" "In5.Cu" "In6.Cu"
			"In7.Cu" "In8.Cu" "In9.Cu" "In10.Cu" "In11.Cu" "In12.Cu" "In13.Cu" "In14.Cu"
			"In15.Cu" "In16.Cu"
		)
		(hatch none 0.5)
		(connect_pads
			(clearance 0)
		)
		(min_thickness 0.25)
		(keepout
			(tracks not_allowed)
			(vias allowed)
			(pads allowed)
			(copperpour not_allowed)
			(footprints allowed)
		)
		(placement
			(enabled no)
			(sheetname "")
		)
		(fill
			(thermal_gap 0.5)
			(thermal_bridge_width 0.5)
			(island_removal_mode 0)
		)
		(polygon
			(pts
				(arc
					(start 122.307096 -221.133924)
					(mid 121.649236 -221.133924)
					(end 122.307096 -221.133924)
				)
			)
		)
	)
	(zone
		(layers "F.Cu" "B.Cu" "In1.Cu" "In2.Cu" "In3.Cu" "In4.Cu" "In5.Cu" "In6.Cu"
			"In7.Cu" "In8.Cu" "In9.Cu" "In10.Cu" "In11.Cu" "In12.Cu" "In13.Cu" "In14.Cu"
			"In15.Cu" "In16.Cu"
		)
		(hatch none 0.5)
		(connect_pads
			(clearance 0)
		)
		(min_thickness 0.25)
		(keepout
			(tracks not_allowed)
			(vias allowed)
			(pads allowed)
			(copperpour not_allowed)
			(footprints allowed)
		)
		(placement
			(enabled no)
			(sheetname "")
		)
		(fill
			(thermal_gap 0.5)
			(thermal_bridge_width 0.5)
			(island_removal_mode 0)
		)
		(polygon
			(pts
				(arc
					(start 347.691456 -214.622634)
					(mid 347.033596 -214.622634)
					(end 347.691456 -214.622634)
				)
			)
		)
	)
	(zone
		(layers "F.Cu" "B.Cu" "In1.Cu" "In2.Cu" "In3.Cu" "In4.Cu" "In5.Cu" "In6.Cu"
			"In7.Cu" "In8.Cu" "In9.Cu" "In10.Cu" "In11.Cu" "In12.Cu" "In13.Cu" "In14.Cu"
			"In15.Cu" "In16.Cu"
		)
		(hatch none 0.5)
		(connect_pads
			(clearance 0)
		)
		(min_thickness 0.25)
		(keepout
			(tracks not_allowed)
			(vias allowed)
			(pads allowed)
			(copperpour not_allowed)
			(footprints allowed)
		)
		(placement
			(enabled no)
			(sheetname "")
		)
		(fill
			(thermal_gap 0.5)
			(thermal_bridge_width 0.5)
			(island_removal_mode 0)
		)
		(polygon
			(pts
				(arc
					(start 97.982278 -286.475424)
					(mid 97.324418 -286.475424)
					(end 97.982278 -286.475424)
				)
			)
		)
	)
	(zone
		(layers "F.Cu" "B.Cu" "In1.Cu" "In2.Cu" "In3.Cu" "In4.Cu" "In5.Cu" "In6.Cu"
			"In7.Cu" "In8.Cu" "In9.Cu" "In10.Cu" "In11.Cu" "In12.Cu" "In13.Cu" "In14.Cu"
			"In15.Cu" "In16.Cu"
		)
		(hatch none 0.5)
		(connect_pads
			(clearance 0)
		)
		(min_thickness 0.25)
		(keepout
			(tracks not_allowed)
			(vias allowed)
			(pads allowed)
			(copperpour not_allowed)
			(footprints allowed)
		)
		(placement
			(enabled no)
			(sheetname "")
		)
		(fill
			(thermal_gap 0.5)
			(thermal_bridge_width 0.5)
			(island_removal_mode 0)
		)
		(polygon
			(pts
				(arc
					(start 380.066296 -285.759652)
					(mid 380.08598 -285.712242)
					(end 380.092712 -285.661354)
				)
				(arc
					(start 380.092712 -285.661354)
					(mid 380.035056 -285.52216)
					(end 379.895862 -285.464504)
				)
				(arc
					(start 379.895862 -285.464504)
					(mid 379.797431 -285.49092)
					(end 379.725428 -285.563056)
				)
				(arc
					(start 379.255782 -286.377126)
					(mid 379.236098 -286.424536)
					(end 379.229366 -286.475424)
				)
				(arc
					(start 379.229366 -286.475424)
					(mid 379.287022 -286.614618)
					(end 379.426216 -286.672274)
				)
				(arc
					(start 379.426216 -286.672274)
					(mid 379.524647 -286.645858)
					(end 379.59665 -286.573722)
				)
			)
		)
	)
	(zone
		(layers "F.Cu" "B.Cu" "In1.Cu" "In2.Cu" "In3.Cu" "In4.Cu" "In5.Cu" "In6.Cu"
			"In7.Cu" "In8.Cu" "In9.Cu" "In10.Cu" "In11.Cu" "In12.Cu" "In13.Cu" "In14.Cu"
			"In15.Cu" "In16.Cu"
		)
		(hatch none 0.5)
		(connect_pads
			(clearance 0)
		)
		(min_thickness 0.25)
		(keepout
			(tracks not_allowed)
			(vias allowed)
			(pads allowed)
			(copperpour not_allowed)
			(footprints allowed)
		)
		(placement
			(enabled no)
			(sheetname "")
		)
		(fill
			(thermal_gap 0.5)
			(thermal_bridge_width 0.5)
			(island_removal_mode 0)
		)
		(polygon
			(pts
				(arc
					(start 374.831356 -175.384968)
					(mid 375.190566 -175.236178)
					(end 375.339356 -174.876968)
				)
				(arc
					(start 375.339356 -174.876968)
					(mid 375.271299 -174.622971)
					(end 375.085356 -174.43704)
				)
				(arc
					(start 374.161304 -173.903386)
					(mid 374.03901 -173.852849)
					(end 373.907812 -173.835568)
				)
				(arc
					(start 373.907304 -173.835568)
					(mid 373.548094 -173.984358)
					(end 373.399304 -174.343568)
				)
				(arc
					(start 373.399304 -174.343568)
					(mid 373.467361 -174.597565)
					(end 373.653304 -174.783496)
				)
				(arc
					(start 374.577356 -175.31715)
					(mid 374.69965 -175.367687)
					(end 374.830848 -175.384968)
				)
			)
		)
	)
	(zone
		(layers "F.Cu" "B.Cu" "In1.Cu" "In2.Cu" "In3.Cu" "In4.Cu" "In5.Cu" "In6.Cu"
			"In7.Cu" "In8.Cu" "In9.Cu" "In10.Cu" "In11.Cu" "In12.Cu" "In13.Cu" "In14.Cu"
			"In15.Cu" "In16.Cu"
		)
		(hatch none 0.5)
		(connect_pads
			(clearance 0)
		)
		(min_thickness 0.25)
		(keepout
			(tracks not_allowed)
			(vias allowed)
			(pads allowed)
			(copperpour not_allowed)
			(footprints allowed)
		)
		(placement
			(enabled no)
			(sheetname "")
		)
		(fill
			(thermal_gap 0.5)
			(thermal_bridge_width 0.5)
			(island_removal_mode 0)
		)
		(polygon
			(pts
				(arc
					(start 127.475742 -221.94774)
					(mid 126.817882 -221.94774)
					(end 127.475742 -221.94774)
				)
			)
		)
	)
	(zone
		(layers "F.Cu" "B.Cu" "In1.Cu" "In2.Cu" "In3.Cu" "In4.Cu" "In5.Cu" "In6.Cu"
			"In7.Cu" "In8.Cu" "In9.Cu" "In10.Cu" "In11.Cu" "In12.Cu" "In13.Cu" "In14.Cu"
			"In15.Cu" "In16.Cu"
		)
		(hatch none 0.5)
		(connect_pads
			(clearance 0)
		)
		(min_thickness 0.25)
		(keepout
			(tracks not_allowed)
			(vias allowed)
			(pads allowed)
			(copperpour not_allowed)
			(footprints allowed)
		)
		(placement
			(enabled no)
			(sheetname "")
		)
		(fill
			(thermal_gap 0.5)
			(thermal_bridge_width 0.5)
			(island_removal_mode 0)
		)
		(polygon
			(pts
				(arc
					(start 100.801678 -288.103056)
					(mid 100.143818 -288.103056)
					(end 100.801678 -288.103056)
				)
			)
		)
	)
	(zone
		(layers "F.Cu" "B.Cu" "In1.Cu" "In2.Cu" "In3.Cu" "In4.Cu" "In5.Cu" "In6.Cu"
			"In7.Cu" "In8.Cu" "In9.Cu" "In10.Cu" "In11.Cu" "In12.Cu" "In13.Cu" "In14.Cu"
			"In15.Cu" "In16.Cu"
		)
		(hatch none 0.5)
		(connect_pads
			(clearance 0)
		)
		(min_thickness 0.25)
		(keepout
			(tracks not_allowed)
			(vias allowed)
			(pads allowed)
			(copperpour not_allowed)
			(footprints allowed)
		)
		(placement
			(enabled no)
			(sheetname "")
		)
		(fill
			(thermal_gap 0.5)
			(thermal_bridge_width 0.5)
			(island_removal_mode 0)
		)
		(polygon
			(pts
				(arc
					(start 119.487696 -221.133924)
					(mid 118.829836 -221.133924)
					(end 119.487696 -221.133924)
				)
			)
		)
	)
	(zone
		(layers "F.Cu" "B.Cu" "In1.Cu" "In2.Cu" "In3.Cu" "In4.Cu" "In5.Cu" "In6.Cu"
			"In7.Cu" "In8.Cu" "In9.Cu" "In10.Cu" "In11.Cu" "In12.Cu" "In13.Cu" "In14.Cu"
			"In15.Cu" "In16.Cu"
		)
		(hatch none 0.5)
		(connect_pads
			(clearance 0)
		)
		(min_thickness 0.25)
		(keepout
			(tracks not_allowed)
			(vias allowed)
			(pads allowed)
			(copperpour not_allowed)
			(footprints allowed)
		)
		(placement
			(enabled no)
			(sheetname "")
		)
		(fill
			(thermal_gap 0.5)
			(thermal_bridge_width 0.5)
			(island_removal_mode 0)
		)
		(polygon
			(pts
				(arc
					(start 107.662218 -275.08073)
					(mid 108.320078 -275.08073)
					(end 107.662218 -275.08073)
				)
			)
		)
	)
	(zone
		(layers "F.Cu" "B.Cu" "In1.Cu" "In2.Cu" "In3.Cu" "In4.Cu" "In5.Cu" "In6.Cu"
			"In7.Cu" "In8.Cu" "In9.Cu" "In10.Cu" "In11.Cu" "In12.Cu" "In13.Cu" "In14.Cu"
			"In15.Cu" "In16.Cu"
		)
		(hatch none 0.5)
		(connect_pads
			(clearance 0)
		)
		(min_thickness 0.25)
		(keepout
			(tracks not_allowed)
			(vias allowed)
			(pads allowed)
			(copperpour not_allowed)
			(footprints allowed)
		)
		(placement
			(enabled no)
			(sheetname "")
		)
		(fill
			(thermal_gap 0.5)
			(thermal_bridge_width 0.5)
			(island_removal_mode 0)
		)
		(polygon
			(pts
				(arc
					(start 352.970592 -280.778204)
					(mid 352.312732 -280.778204)
					(end 352.970592 -280.778204)
				)
			)
		)
	)
	(zone
		(layers "F.Cu" "B.Cu" "In1.Cu" "In2.Cu" "In3.Cu" "In4.Cu" "In5.Cu" "In6.Cu"
			"In7.Cu" "In8.Cu" "In9.Cu" "In10.Cu" "In11.Cu" "In12.Cu" "In13.Cu" "In14.Cu"
			"In15.Cu" "In16.Cu"
		)
		(hatch none 0.5)
		(connect_pads
			(clearance 0)
		)
		(min_thickness 0.25)
		(keepout
			(tracks not_allowed)
			(vias allowed)
			(pads allowed)
			(copperpour not_allowed)
			(footprints allowed)
		)
		(placement
			(enabled no)
			(sheetname "")
		)
		(fill
			(thermal_gap 0.5)
			(thermal_bridge_width 0.5)
			(island_removal_mode 0)
		)
		(polygon
			(pts
				(arc
					(start 121.836942 -218.692222)
					(mid 121.179082 -218.692222)
					(end 121.836942 -218.692222)
				)
			)
		)
	)
	(zone
		(layers "F.Cu" "B.Cu" "In1.Cu" "In2.Cu" "In3.Cu" "In4.Cu" "In5.Cu" "In6.Cu"
			"In7.Cu" "In8.Cu" "In9.Cu" "In10.Cu" "In11.Cu" "In12.Cu" "In13.Cu" "In14.Cu"
			"In15.Cu" "In16.Cu"
		)
		(hatch none 0.5)
		(connect_pads
			(clearance 0)
		)
		(min_thickness 0.25)
		(keepout
			(tracks not_allowed)
			(vias allowed)
			(pads allowed)
			(copperpour not_allowed)
			(footprints allowed)
		)
		(placement
			(enabled no)
			(sheetname "")
		)
		(fill
			(thermal_gap 0.5)
			(thermal_bridge_width 0.5)
			(island_removal_mode 0)
		)
		(polygon
			(pts
				(arc
					(start 100.801678 -284.847538)
					(mid 100.143818 -284.847538)
					(end 100.801678 -284.847538)
				)
			)
		)
	)
	(zone
		(layers "F.Cu" "B.Cu" "In1.Cu" "In2.Cu" "In3.Cu" "In4.Cu" "In5.Cu" "In6.Cu"
			"In7.Cu" "In8.Cu" "In9.Cu" "In10.Cu" "In11.Cu" "In12.Cu" "In13.Cu" "In14.Cu"
			"In15.Cu" "In16.Cu"
		)
		(hatch none 0.5)
		(connect_pads
			(clearance 0)
		)
		(min_thickness 0.25)
		(keepout
			(tracks not_allowed)
			(vias allowed)
			(pads allowed)
			(copperpour not_allowed)
			(footprints allowed)
		)
		(placement
			(enabled no)
			(sheetname "")
		)
		(fill
			(thermal_gap 0.5)
			(thermal_bridge_width 0.5)
			(island_removal_mode 0)
		)
		(polygon
			(pts
				(arc
					(start 101.93528 -213.646766)
					(mid 101.867572 -213.574915)
					(end 101.772466 -213.548468)
				)
				(arc
					(start 101.772466 -213.548468)
					(mid 101.642252 -213.602404)
					(end 101.588316 -213.732618)
				)
				(arc
					(start 101.588316 -213.732618)
					(mid 101.593767 -213.776839)
					(end 101.609652 -213.81847)
				)
				(arc
					(start 102.079044 -214.708486)
					(mid 102.146752 -214.780337)
					(end 102.241858 -214.806784)
				)
				(arc
					(start 102.241858 -214.806784)
					(mid 102.372072 -214.752848)
					(end 102.426008 -214.622634)
				)
				(arc
					(start 102.426008 -214.622634)
					(mid 102.420557 -214.578413)
					(end 102.404672 -214.536782)
				)
			)
		)
	)
	(zone
		(layers "F.Cu" "B.Cu" "In1.Cu" "In2.Cu" "In3.Cu" "In4.Cu" "In5.Cu" "In6.Cu"
			"In7.Cu" "In8.Cu" "In9.Cu" "In10.Cu" "In11.Cu" "In12.Cu" "In13.Cu" "In14.Cu"
			"In15.Cu" "In16.Cu"
		)
		(hatch none 0.5)
		(connect_pads
			(clearance 0)
		)
		(min_thickness 0.25)
		(keepout
			(tracks not_allowed)
			(vias allowed)
			(pads allowed)
			(copperpour not_allowed)
			(footprints allowed)
		)
		(placement
			(enabled no)
			(sheetname "")
		)
		(fill
			(thermal_gap 0.5)
			(thermal_bridge_width 0.5)
			(island_removal_mode 0)
		)
		(polygon
			(pts
				(arc
					(start 355.85019 -60.814966)
					(mid 355.46919 -61.195966)
					(end 355.85019 -61.576966)
				)
				(arc
					(start 356.71379 -61.576966)
					(mid 357.09479 -61.195966)
					(end 356.71379 -60.814966)
				)
			)
		)
	)
	(zone
		(layers "F.Cu" "B.Cu" "In1.Cu" "In2.Cu" "In3.Cu" "In4.Cu" "In5.Cu" "In6.Cu"
			"In7.Cu" "In8.Cu" "In9.Cu" "In10.Cu" "In11.Cu" "In12.Cu" "In13.Cu" "In14.Cu"
			"In15.Cu" "In16.Cu"
		)
		(hatch none 0.5)
		(connect_pads
			(clearance 0)
		)
		(min_thickness 0.25)
		(keepout
			(tracks not_allowed)
			(vias allowed)
			(pads allowed)
			(copperpour not_allowed)
			(footprints allowed)
		)
		(placement
			(enabled no)
			(sheetname "")
		)
		(fill
			(thermal_gap 0.5)
			(thermal_bridge_width 0.5)
			(island_removal_mode 0)
		)
		(polygon
			(pts
				(arc
					(start 364.44936 -217.97645)
					(mid 364.469044 -217.92904)
					(end 364.475776 -217.878152)
				)
				(arc
					(start 364.475776 -217.878152)
					(mid 364.41812 -217.738958)
					(end 364.278926 -217.681302)
				)
				(arc
					(start 364.278926 -217.681302)
					(mid 364.180495 -217.707718)
					(end 364.108492 -217.779854)
				)
				(arc
					(start 363.638846 -218.593924)
					(mid 363.619162 -218.641334)
					(end 363.61243 -218.692222)
				)
				(arc
					(start 363.61243 -218.692222)
					(mid 363.670086 -218.831416)
					(end 363.80928 -218.889072)
				)
				(arc
					(start 363.80928 -218.889072)
					(mid 363.907711 -218.862656)
					(end 363.979714 -218.79052)
				)
			)
		)
	)
	(zone
		(layers "F.Cu" "B.Cu" "In1.Cu" "In2.Cu" "In3.Cu" "In4.Cu" "In5.Cu" "In6.Cu"
			"In7.Cu" "In8.Cu" "In9.Cu" "In10.Cu" "In11.Cu" "In12.Cu" "In13.Cu" "In14.Cu"
			"In15.Cu" "In16.Cu"
		)
		(hatch none 0.5)
		(connect_pads
			(clearance 0)
		)
		(min_thickness 0.25)
		(keepout
			(tracks not_allowed)
			(vias allowed)
			(pads allowed)
			(copperpour not_allowed)
			(footprints allowed)
		)
		(placement
			(enabled no)
			(sheetname "")
		)
		(fill
			(thermal_gap 0.5)
			(thermal_bridge_width 0.5)
			(island_removal_mode 0)
		)
		(polygon
			(pts
				(arc
					(start 335.895696 -282.307538)
					(mid 335.823707 -282.235379)
					(end 335.725262 -282.208986)
				)
				(arc
					(start 335.725262 -282.208986)
					(mid 335.586068 -282.266642)
					(end 335.528412 -282.405836)
				)
				(arc
					(start 335.528412 -282.405836)
					(mid 335.535169 -282.456717)
					(end 335.554828 -282.504134)
				)
				(arc
					(start 336.024728 -283.318204)
					(mid 336.096717 -283.390363)
					(end 336.195162 -283.416756)
				)
				(arc
					(start 336.195162 -283.416756)
					(mid 336.334356 -283.3591)
					(end 336.392012 -283.219906)
				)
				(arc
					(start 336.392012 -283.219906)
					(mid 336.385255 -283.169025)
					(end 336.365596 -283.121608)
				)
			)
		)
	)
	(zone
		(layers "F.Cu" "B.Cu" "In1.Cu" "In2.Cu" "In3.Cu" "In4.Cu" "In5.Cu" "In6.Cu"
			"In7.Cu" "In8.Cu" "In9.Cu" "In10.Cu" "In11.Cu" "In12.Cu" "In13.Cu" "In14.Cu"
			"In15.Cu" "In16.Cu"
		)
		(hatch none 0.5)
		(connect_pads
			(clearance 0)
		)
		(min_thickness 0.25)
		(keepout
			(tracks not_allowed)
			(vias allowed)
			(pads allowed)
			(copperpour not_allowed)
			(footprints allowed)
		)
		(placement
			(enabled no)
			(sheetname "")
		)
		(fill
			(thermal_gap 0.5)
			(thermal_bridge_width 0.5)
			(island_removal_mode 0)
		)
		(polygon
			(pts
				(xy 351.76714 -37.8206)
				(arc
					(start 351.83826 -36.80714)
					(mid 352.244911 -36.453861)
					(end 352.59772 -36.860988)
				)
				(arc
					(start 352.526854 -37.874702)
					(mid 352.120325 -38.229445)
					(end 351.76714 -37.821616)
				)
			)
		)
	)
	(zone
		(layers "F.Cu" "B.Cu" "In1.Cu" "In2.Cu" "In3.Cu" "In4.Cu" "In5.Cu" "In6.Cu"
			"In7.Cu" "In8.Cu" "In9.Cu" "In10.Cu" "In11.Cu" "In12.Cu" "In13.Cu" "In14.Cu"
			"In15.Cu" "In16.Cu"
		)
		(hatch none 0.5)
		(connect_pads
			(clearance 0)
		)
		(min_thickness 0.25)
		(keepout
			(tracks not_allowed)
			(vias allowed)
			(pads allowed)
			(copperpour not_allowed)
			(footprints allowed)
		)
		(placement
			(enabled no)
			(sheetname "")
		)
		(fill
			(thermal_gap 0.5)
			(thermal_bridge_width 0.5)
			(island_removal_mode 0)
		)
		(polygon
			(pts
				(arc
					(start 97.042478 -288.103056)
					(mid 96.384618 -288.103056)
					(end 97.042478 -288.103056)
				)
			)
		)
	)
	(zone
		(layers "F.Cu" "B.Cu" "In1.Cu" "In2.Cu" "In3.Cu" "In4.Cu" "In5.Cu" "In6.Cu"
			"In7.Cu" "In8.Cu" "In9.Cu" "In10.Cu" "In11.Cu" "In12.Cu" "In13.Cu" "In14.Cu"
			"In15.Cu" "In16.Cu"
		)
		(hatch none 0.5)
		(connect_pads
			(clearance 0)
		)
		(min_thickness 0.25)
		(keepout
			(tracks not_allowed)
			(vias allowed)
			(pads allowed)
			(copperpour not_allowed)
			(footprints allowed)
		)
		(placement
			(enabled no)
			(sheetname "")
		)
		(fill
			(thermal_gap 0.5)
			(thermal_bridge_width 0.5)
			(island_removal_mode 0)
		)
		(polygon
			(pts
				(arc
					(start 128.257554 -216.966292)
					(mid 128.185565 -216.894133)
					(end 128.08712 -216.86774)
				)
				(arc
					(start 128.08712 -216.86774)
					(mid 127.947926 -216.925396)
					(end 127.89027 -217.06459)
				)
				(arc
					(start 127.89027 -217.06459)
					(mid 127.897027 -217.115471)
					(end 127.916686 -217.162888)
				)
				(arc
					(start 128.386332 -217.976704)
					(mid 128.458321 -218.048863)
					(end 128.556766 -218.075256)
				)
				(arc
					(start 128.556766 -218.075256)
					(mid 128.69596 -218.0176)
					(end 128.753616 -217.878406)
				)
				(arc
					(start 128.753616 -217.878406)
					(mid 128.746859 -217.827525)
					(end 128.7272 -217.780108)
				)
			)
		)
	)
	(zone
		(layers "F.Cu" "B.Cu" "In1.Cu" "In2.Cu" "In3.Cu" "In4.Cu" "In5.Cu" "In6.Cu"
			"In7.Cu" "In8.Cu" "In9.Cu" "In10.Cu" "In11.Cu" "In12.Cu" "In13.Cu" "In14.Cu"
			"In15.Cu" "In16.Cu"
		)
		(hatch none 0.5)
		(connect_pads
			(clearance 0)
		)
		(min_thickness 0.25)
		(keepout
			(tracks not_allowed)
			(vias allowed)
			(pads allowed)
			(copperpour not_allowed)
			(footprints allowed)
		)
		(placement
			(enabled no)
			(sheetname "")
		)
		(fill
			(thermal_gap 0.5)
			(thermal_bridge_width 0.5)
			(island_removal_mode 0)
		)
		(polygon
			(pts
				(arc
					(start 342.601296 -83.942174)
					(mid 342.982296 -83.561174)
					(end 342.601296 -83.180174)
				)
				(arc
					(start 341.737696 -83.180174)
					(mid 341.356696 -83.561174)
					(end 341.737696 -83.942174)
				)
			)
		)
	)
	(zone
		(layers "F.Cu" "B.Cu" "In1.Cu" "In2.Cu" "In3.Cu" "In4.Cu" "In5.Cu" "In6.Cu"
			"In7.Cu" "In8.Cu" "In9.Cu" "In10.Cu" "In11.Cu" "In12.Cu" "In13.Cu" "In14.Cu"
			"In15.Cu" "In16.Cu"
		)
		(hatch none 0.5)
		(connect_pads
			(clearance 0)
		)
		(min_thickness 0.25)
		(keepout
			(tracks not_allowed)
			(vias allowed)
			(pads allowed)
			(copperpour not_allowed)
			(footprints allowed)
		)
		(placement
			(enabled no)
			(sheetname "")
		)
		(fill
			(thermal_gap 0.5)
			(thermal_bridge_width 0.5)
			(island_removal_mode 0)
		)
		(polygon
			(pts
				(arc
					(start 94.034864 -285.661354)
					(mid 94.692724 -285.661354)
					(end 94.034864 -285.661354)
				)
			)
		)
	)
	(zone
		(layers "F.Cu" "B.Cu" "In1.Cu" "In2.Cu" "In3.Cu" "In4.Cu" "In5.Cu" "In6.Cu"
			"In7.Cu" "In8.Cu" "In9.Cu" "In10.Cu" "In11.Cu" "In12.Cu" "In13.Cu" "In14.Cu"
			"In15.Cu" "In16.Cu"
		)
		(hatch none 0.5)
		(connect_pads
			(clearance 0)
		)
		(min_thickness 0.25)
		(keepout
			(tracks not_allowed)
			(vias allowed)
			(pads allowed)
			(copperpour not_allowed)
			(footprints allowed)
		)
		(placement
			(enabled no)
			(sheetname "")
		)
		(fill
			(thermal_gap 0.5)
			(thermal_bridge_width 0.5)
			(island_removal_mode 0)
		)
		(polygon
			(pts
				(arc
					(start 105.640124 -412.747968)
					(mid 105.259124 -412.366968)
					(end 104.878124 -412.747968)
				)
				(arc
					(start 104.878124 -413.611568)
					(mid 105.259124 -413.992568)
					(end 105.640124 -413.611568)
				)
			)
		)
	)
	(zone
		(layers "F.Cu" "B.Cu" "In1.Cu" "In2.Cu" "In3.Cu" "In4.Cu" "In5.Cu" "In6.Cu"
			"In7.Cu" "In8.Cu" "In9.Cu" "In10.Cu" "In11.Cu" "In12.Cu" "In13.Cu" "In14.Cu"
			"In15.Cu" "In16.Cu"
		)
		(hatch none 0.5)
		(connect_pads
			(clearance 0)
		)
		(min_thickness 0.25)
		(keepout
			(tracks not_allowed)
			(vias allowed)
			(pads allowed)
			(copperpour not_allowed)
			(footprints allowed)
		)
		(placement
			(enabled no)
			(sheetname "")
		)
		(fill
			(thermal_gap 0.5)
			(thermal_bridge_width 0.5)
			(island_removal_mode 0)
		)
		(polygon
			(pts
				(arc
					(start 109.461554 -220.22181)
					(mid 109.389565 -220.149651)
					(end 109.29112 -220.123258)
				)
				(arc
					(start 109.29112 -220.123258)
					(mid 109.151926 -220.180914)
					(end 109.09427 -220.320108)
				)
				(arc
					(start 109.09427 -220.320108)
					(mid 109.101027 -220.370989)
					(end 109.120686 -220.418406)
				)
				(arc
					(start 109.590332 -221.232222)
					(mid 109.662321 -221.304381)
					(end 109.760766 -221.330774)
				)
				(arc
					(start 109.760766 -221.330774)
					(mid 109.89996 -221.273118)
					(end 109.957616 -221.133924)
				)
				(arc
					(start 109.957616 -221.133924)
					(mid 109.950859 -221.083043)
					(end 109.9312 -221.035626)
				)
			)
		)
	)
	(zone
		(layers "F.Cu" "B.Cu" "In1.Cu" "In2.Cu" "In3.Cu" "In4.Cu" "In5.Cu" "In6.Cu"
			"In7.Cu" "In8.Cu" "In9.Cu" "In10.Cu" "In11.Cu" "In12.Cu" "In13.Cu" "In14.Cu"
			"In15.Cu" "In16.Cu"
		)
		(hatch none 0.5)
		(connect_pads
			(clearance 0)
		)
		(min_thickness 0.25)
		(keepout
			(tracks not_allowed)
			(vias allowed)
			(pads allowed)
			(copperpour not_allowed)
			(footprints allowed)
		)
		(placement
			(enabled no)
			(sheetname "")
		)
		(fill
			(thermal_gap 0.5)
			(thermal_bridge_width 0.5)
			(island_removal_mode 0)
		)
		(polygon
			(pts
				(arc
					(start 127.627634 -406.62352)
					(mid 127.246634 -407.00452)
					(end 127.627634 -407.38552)
				)
				(arc
					(start 128.491234 -407.38552)
					(mid 128.872234 -407.00452)
					(end 128.491234 -406.62352)
				)
			)
		)
	)
	(zone
		(layers "F.Cu" "B.Cu" "In1.Cu" "In2.Cu" "In3.Cu" "In4.Cu" "In5.Cu" "In6.Cu"
			"In7.Cu" "In8.Cu" "In9.Cu" "In10.Cu" "In11.Cu" "In12.Cu" "In13.Cu" "In14.Cu"
			"In15.Cu" "In16.Cu"
		)
		(hatch none 0.5)
		(connect_pads
			(clearance 0)
		)
		(min_thickness 0.25)
		(keepout
			(tracks not_allowed)
			(vias allowed)
			(pads allowed)
			(copperpour not_allowed)
			(footprints allowed)
		)
		(placement
			(enabled no)
			(sheetname "")
		)
		(fill
			(thermal_gap 0.5)
			(thermal_bridge_width 0.5)
			(island_removal_mode 0)
		)
		(polygon
			(pts
				(arc
					(start 391.14857 -406.62352)
					(mid 390.76757 -407.00452)
					(end 391.14857 -407.38552)
				)
				(arc
					(start 392.01217 -407.38552)
					(mid 392.39317 -407.00452)
					(end 392.01217 -406.62352)
				)
			)
		)
	)
	(zone
		(layers "F.Cu" "B.Cu" "In1.Cu" "In2.Cu" "In3.Cu" "In4.Cu" "In5.Cu" "In6.Cu"
			"In7.Cu" "In8.Cu" "In9.Cu" "In10.Cu" "In11.Cu" "In12.Cu" "In13.Cu" "In14.Cu"
			"In15.Cu" "In16.Cu"
		)
		(hatch none 0.5)
		(connect_pads
			(clearance 0)
		)
		(min_thickness 0.25)
		(keepout
			(tracks not_allowed)
			(vias allowed)
			(pads allowed)
			(copperpour not_allowed)
			(footprints allowed)
		)
		(placement
			(enabled no)
			(sheetname "")
		)
		(fill
			(thermal_gap 0.5)
			(thermal_bridge_width 0.5)
			(island_removal_mode 0)
		)
		(polygon
			(pts
				(arc
					(start 112.438942 -225.203258)
					(mid 111.781082 -225.203258)
					(end 112.438942 -225.203258)
				)
			)
		)
	)
	(zone
		(layers "F.Cu" "B.Cu" "In1.Cu" "In2.Cu" "In3.Cu" "In4.Cu" "In5.Cu" "In6.Cu"
			"In7.Cu" "In8.Cu" "In9.Cu" "In10.Cu" "In11.Cu" "In12.Cu" "In13.Cu" "In14.Cu"
			"In15.Cu" "In16.Cu"
		)
		(hatch none 0.5)
		(connect_pads
			(clearance 0)
		)
		(min_thickness 0.25)
		(keepout
			(tracks not_allowed)
			(vias allowed)
			(pads allowed)
			(copperpour not_allowed)
			(footprints allowed)
		)
		(placement
			(enabled no)
			(sheetname "")
		)
		(fill
			(thermal_gap 0.5)
			(thermal_bridge_width 0.5)
			(island_removal_mode 0)
		)
		(polygon
			(pts
				(arc
					(start 127.006096 -224.389442)
					(mid 126.348236 -224.389442)
					(end 127.006096 -224.389442)
				)
			)
		)
	)
	(zone
		(layers "F.Cu" "B.Cu" "In1.Cu" "In2.Cu" "In3.Cu" "In4.Cu" "In5.Cu" "In6.Cu"
			"In7.Cu" "In8.Cu" "In9.Cu" "In10.Cu" "In11.Cu" "In12.Cu" "In13.Cu" "In14.Cu"
			"In15.Cu" "In16.Cu"
		)
		(hatch none 0.5)
		(connect_pads
			(clearance 0)
		)
		(min_thickness 0.25)
		(keepout
			(tracks not_allowed)
			(vias allowed)
			(pads allowed)
			(copperpour not_allowed)
			(footprints allowed)
		)
		(placement
			(enabled no)
			(sheetname "")
		)
		(fill
			(thermal_gap 0.5)
			(thermal_bridge_width 0.5)
			(island_removal_mode 0)
		)
		(polygon
			(pts
				(arc
					(start 89.414096 -221.133924)
					(mid 88.756236 -221.133924)
					(end 89.414096 -221.133924)
				)
			)
		)
	)
	(zone
		(layers "F.Cu" "B.Cu" "In1.Cu" "In2.Cu" "In3.Cu" "In4.Cu" "In5.Cu" "In6.Cu"
			"In7.Cu" "In8.Cu" "In9.Cu" "In10.Cu" "In11.Cu" "In12.Cu" "In13.Cu" "In14.Cu"
			"In15.Cu" "In16.Cu"
		)
		(hatch none 0.5)
		(connect_pads
			(clearance 0)
		)
		(min_thickness 0.25)
		(keepout
			(tracks not_allowed)
			(vias allowed)
			(pads allowed)
			(copperpour not_allowed)
			(footprints allowed)
		)
		(placement
			(enabled no)
			(sheetname "")
		)
		(fill
			(thermal_gap 0.5)
			(thermal_bridge_width 0.5)
			(island_removal_mode 0)
		)
		(polygon
			(pts
				(arc
					(start 373.066564 -224.389442)
					(mid 372.408704 -224.389442)
					(end 373.066564 -224.389442)
				)
			)
		)
	)
	(zone
		(layers "F.Cu" "B.Cu" "In1.Cu" "In2.Cu" "In3.Cu" "In4.Cu" "In5.Cu" "In6.Cu"
			"In7.Cu" "In8.Cu" "In9.Cu" "In10.Cu" "In11.Cu" "In12.Cu" "In13.Cu" "In14.Cu"
			"In15.Cu" "In16.Cu"
		)
		(hatch none 0.5)
		(connect_pads
			(clearance 0)
		)
		(min_thickness 0.25)
		(keepout
			(tracks not_allowed)
			(vias allowed)
			(pads allowed)
			(copperpour not_allowed)
			(footprints allowed)
		)
		(placement
			(enabled no)
			(sheetname "")
		)
		(fill
			(thermal_gap 0.5)
			(thermal_bridge_width 0.5)
			(island_removal_mode 0)
		)
		(polygon
			(pts
				(arc
					(start 344.982546 -283.219906)
					(mid 344.324686 -283.219906)
					(end 344.982546 -283.219906)
				)
			)
		)
	)
	(zone
		(layers "F.Cu" "B.Cu" "In1.Cu" "In2.Cu" "In3.Cu" "In4.Cu" "In5.Cu" "In6.Cu"
			"In7.Cu" "In8.Cu" "In9.Cu" "In10.Cu" "In11.Cu" "In12.Cu" "In13.Cu" "In14.Cu"
			"In15.Cu" "In16.Cu"
		)
		(hatch none 0.5)
		(connect_pads
			(clearance 0)
		)
		(min_thickness 0.25)
		(keepout
			(tracks not_allowed)
			(vias allowed)
			(pads allowed)
			(copperpour not_allowed)
			(footprints allowed)
		)
		(placement
			(enabled no)
			(sheetname "")
		)
		(fill
			(thermal_gap 0.5)
			(thermal_bridge_width 0.5)
			(island_removal_mode 0)
		)
		(polygon
			(pts
				(arc
					(start 350.04121 -223.575626)
					(mid 349.38335 -223.575626)
					(end 350.04121 -223.575626)
				)
			)
		)
	)
	(zone
		(layers "F.Cu" "B.Cu" "In1.Cu" "In2.Cu" "In3.Cu" "In4.Cu" "In5.Cu" "In6.Cu"
			"In7.Cu" "In8.Cu" "In9.Cu" "In10.Cu" "In11.Cu" "In12.Cu" "In13.Cu" "In14.Cu"
			"In15.Cu" "In16.Cu"
		)
		(hatch none 0.5)
		(connect_pads
			(clearance 0)
		)
		(min_thickness 0.25)
		(keepout
			(tracks not_allowed)
			(vias allowed)
			(pads allowed)
			(copperpour not_allowed)
			(footprints allowed)
		)
		(placement
			(enabled no)
			(sheetname "")
		)
		(fill
			(thermal_gap 0.5)
			(thermal_bridge_width 0.5)
			(island_removal_mode 0)
		)
		(polygon
			(pts
				(arc
					(start 102.383082 -215.436704)
					(mid 103.040942 -215.436704)
					(end 102.383082 -215.436704)
				)
			)
		)
	)
	(zone
		(layers "F.Cu" "B.Cu" "In1.Cu" "In2.Cu" "In3.Cu" "In4.Cu" "In5.Cu" "In6.Cu"
			"In7.Cu" "In8.Cu" "In9.Cu" "In10.Cu" "In11.Cu" "In12.Cu" "In13.Cu" "In14.Cu"
			"In15.Cu" "In16.Cu"
		)
		(hatch none 0.5)
		(connect_pads
			(clearance 0)
		)
		(min_thickness 0.25)
		(keepout
			(tracks not_allowed)
			(vias allowed)
			(pads allowed)
			(copperpour not_allowed)
			(footprints allowed)
		)
		(placement
			(enabled no)
			(sheetname "")
		)
		(fill
			(thermal_gap 0.5)
			(thermal_bridge_width 0.5)
			(island_removal_mode 0)
		)
		(polygon
			(pts
				(arc
					(start 356.260146 -278.336502)
					(mid 355.602286 -278.336502)
					(end 356.260146 -278.336502)
				)
			)
		)
	)
	(zone
		(layers "F.Cu" "B.Cu" "In1.Cu" "In2.Cu" "In3.Cu" "In4.Cu" "In5.Cu" "In6.Cu"
			"In7.Cu" "In8.Cu" "In9.Cu" "In10.Cu" "In11.Cu" "In12.Cu" "In13.Cu" "In14.Cu"
			"In15.Cu" "In16.Cu"
		)
		(hatch none 0.5)
		(connect_pads
			(clearance 0)
		)
		(min_thickness 0.25)
		(keepout
			(tracks not_allowed)
			(vias allowed)
			(pads allowed)
			(copperpour not_allowed)
			(footprints allowed)
		)
		(placement
			(enabled no)
			(sheetname "")
		)
		(fill
			(thermal_gap 0.5)
			(thermal_bridge_width 0.5)
			(island_removal_mode 0)
		)
		(polygon
			(pts
				(arc
					(start 133.114542 -225.203258)
					(mid 132.456682 -225.203258)
					(end 133.114542 -225.203258)
				)
			)
		)
	)
	(zone
		(layers "F.Cu" "B.Cu" "In1.Cu" "In2.Cu" "In3.Cu" "In4.Cu" "In5.Cu" "In6.Cu"
			"In7.Cu" "In8.Cu" "In9.Cu" "In10.Cu" "In11.Cu" "In12.Cu" "In13.Cu" "In14.Cu"
			"In15.Cu" "In16.Cu"
		)
		(hatch none 0.5)
		(connect_pads
			(clearance 0)
		)
		(min_thickness 0.25)
		(keepout
			(tracks not_allowed)
			(vias allowed)
			(pads allowed)
			(copperpour not_allowed)
			(footprints allowed)
		)
		(placement
			(enabled no)
			(sheetname "")
		)
		(fill
			(thermal_gap 0.5)
			(thermal_bridge_width 0.5)
			(island_removal_mode 0)
		)
		(polygon
			(pts
				(arc
					(start 92.045282 -220.319854)
					(mid 92.703142 -220.319854)
					(end 92.045282 -220.319854)
				)
			)
		)
	)
	(zone
		(layers "F.Cu" "B.Cu" "In1.Cu" "In2.Cu" "In3.Cu" "In4.Cu" "In5.Cu" "In6.Cu"
			"In7.Cu" "In8.Cu" "In9.Cu" "In10.Cu" "In11.Cu" "In12.Cu" "In13.Cu" "In14.Cu"
			"In15.Cu" "In16.Cu"
		)
		(hatch none 0.5)
		(connect_pads
			(clearance 0)
		)
		(min_thickness 0.25)
		(keepout
			(tracks not_allowed)
			(vias allowed)
			(pads allowed)
			(copperpour not_allowed)
			(footprints allowed)
		)
		(placement
			(enabled no)
			(sheetname "")
		)
		(fill
			(thermal_gap 0.5)
			(thermal_bridge_width 0.5)
			(island_removal_mode 0)
		)
		(polygon
			(pts
				(arc
					(start 367.537746 -284.847538)
					(mid 366.879886 -284.847538)
					(end 367.537746 -284.847538)
				)
			)
		)
	)
	(zone
		(layers "F.Cu" "B.Cu" "In1.Cu" "In2.Cu" "In3.Cu" "In4.Cu" "In5.Cu" "In6.Cu"
			"In7.Cu" "In8.Cu" "In9.Cu" "In10.Cu" "In11.Cu" "In12.Cu" "In13.Cu" "In14.Cu"
			"In15.Cu" "In16.Cu"
		)
		(hatch none 0.5)
		(connect_pads
			(clearance 0)
		)
		(min_thickness 0.25)
		(keepout
			(tracks not_allowed)
			(vias allowed)
			(pads allowed)
			(copperpour not_allowed)
			(footprints allowed)
		)
		(placement
			(enabled no)
			(sheetname "")
		)
		(fill
			(thermal_gap 0.5)
			(thermal_bridge_width 0.5)
			(island_removal_mode 0)
		)
		(polygon
			(pts
				(arc
					(start 153.850594 -400.477228)
					(mid 153.469594 -400.858228)
					(end 153.850594 -401.239228)
				)
				(arc
					(start 154.714194 -401.239228)
					(mid 155.095194 -400.858228)
					(end 154.714194 -400.477228)
				)
			)
		)
	)
	(zone
		(layers "F.Cu" "B.Cu" "In1.Cu" "In2.Cu" "In3.Cu" "In4.Cu" "In5.Cu" "In6.Cu"
			"In7.Cu" "In8.Cu" "In9.Cu" "In10.Cu" "In11.Cu" "In12.Cu" "In13.Cu" "In14.Cu"
			"In15.Cu" "In16.Cu"
		)
		(hatch none 0.5)
		(connect_pads
			(clearance 0)
		)
		(min_thickness 0.25)
		(keepout
			(tracks not_allowed)
			(vias allowed)
			(pads allowed)
			(copperpour not_allowed)
			(footprints allowed)
		)
		(placement
			(enabled no)
			(sheetname "")
		)
		(fill
			(thermal_gap 0.5)
			(thermal_bridge_width 0.5)
			(island_removal_mode 0)
		)
		(polygon
			(pts
				(arc
					(start 378.23521 -217.064336)
					(mid 377.57735 -217.064336)
					(end 378.23521 -217.064336)
				)
			)
		)
	)
	(zone
		(layers "F.Cu" "B.Cu" "In1.Cu" "In2.Cu" "In3.Cu" "In4.Cu" "In5.Cu" "In6.Cu"
			"In7.Cu" "In8.Cu" "In9.Cu" "In10.Cu" "In11.Cu" "In12.Cu" "In13.Cu" "In14.Cu"
			"In15.Cu" "In16.Cu"
		)
		(hatch none 0.5)
		(connect_pads
			(clearance 0)
		)
		(min_thickness 0.25)
		(keepout
			(tracks not_allowed)
			(vias allowed)
			(pads allowed)
			(copperpour not_allowed)
			(footprints allowed)
		)
		(placement
			(enabled no)
			(sheetname "")
		)
		(fill
			(thermal_gap 0.5)
			(thermal_bridge_width 0.5)
			(island_removal_mode 0)
		)
		(polygon
			(pts
				(arc
					(start 405.11857 -403.502876)
					(mid 404.73757 -403.883876)
					(end 405.11857 -404.264876)
				)
				(arc
					(start 405.98217 -404.264876)
					(mid 406.36317 -403.883876)
					(end 405.98217 -403.502876)
				)
			)
		)
	)
	(zone
		(layers "F.Cu" "B.Cu" "In1.Cu" "In2.Cu" "In3.Cu" "In4.Cu" "In5.Cu" "In6.Cu"
			"In7.Cu" "In8.Cu" "In9.Cu" "In10.Cu" "In11.Cu" "In12.Cu" "In13.Cu" "In14.Cu"
			"In15.Cu" "In16.Cu"
		)
		(hatch none 0.5)
		(connect_pads
			(clearance 0)
		)
		(min_thickness 0.25)
		(keepout
			(tracks not_allowed)
			(vias allowed)
			(pads allowed)
			(copperpour not_allowed)
			(footprints allowed)
		)
		(placement
			(enabled no)
			(sheetname "")
		)
		(fill
			(thermal_gap 0.5)
			(thermal_bridge_width 0.5)
			(island_removal_mode 0)
		)
		(polygon
			(pts
				(arc
					(start 380.224792 -285.661354)
					(mid 379.566932 -285.661354)
					(end 380.224792 -285.661354)
				)
			)
		)
	)
	(zone
		(layers "F.Cu" "B.Cu" "In1.Cu" "In2.Cu" "In3.Cu" "In4.Cu" "In5.Cu" "In6.Cu"
			"In7.Cu" "In8.Cu" "In9.Cu" "In10.Cu" "In11.Cu" "In12.Cu" "In13.Cu" "In14.Cu"
			"In15.Cu" "In16.Cu"
		)
		(hatch none 0.5)
		(connect_pads
			(clearance 0)
		)
		(min_thickness 0.25)
		(keepout
			(tracks not_allowed)
			(vias allowed)
			(pads allowed)
			(copperpour not_allowed)
			(footprints allowed)
		)
		(placement
			(enabled no)
			(sheetname "")
		)
		(fill
			(thermal_gap 0.5)
			(thermal_bridge_width 0.5)
			(island_removal_mode 0)
		)
		(polygon
			(pts
				(arc
					(start 383.484882 -289.015424)
					(mid 383.556871 -289.087583)
					(end 383.655316 -289.113976)
				)
				(arc
					(start 383.655316 -289.113976)
					(mid 383.79451 -289.05632)
					(end 383.852166 -288.917126)
				)
				(arc
					(start 383.852166 -288.917126)
					(mid 383.845409 -288.866245)
					(end 383.82575 -288.818828)
				)
				(arc
					(start 383.35585 -288.004758)
					(mid 383.283861 -287.932599)
					(end 383.185416 -287.906206)
				)
				(arc
					(start 383.185416 -287.906206)
					(mid 383.046222 -287.963862)
					(end 382.988566 -288.103056)
				)
				(arc
					(start 382.988566 -288.103056)
					(mid 382.995323 -288.153937)
					(end 383.014982 -288.201354)
				)
			)
		)
	)
	(zone
		(layers "F.Cu" "B.Cu" "In1.Cu" "In2.Cu" "In3.Cu" "In4.Cu" "In5.Cu" "In6.Cu"
			"In7.Cu" "In8.Cu" "In9.Cu" "In10.Cu" "In11.Cu" "In12.Cu" "In13.Cu" "In14.Cu"
			"In15.Cu" "In16.Cu"
		)
		(hatch none 0.5)
		(connect_pads
			(clearance 0)
		)
		(min_thickness 0.25)
		(keepout
			(tracks not_allowed)
			(vias allowed)
			(pads allowed)
			(copperpour not_allowed)
			(footprints allowed)
		)
		(placement
			(enabled no)
			(sheetname "")
		)
		(fill
			(thermal_gap 0.5)
			(thermal_bridge_width 0.5)
			(island_removal_mode 0)
		)
		(polygon
			(pts
				(arc
					(start 51.941476 -4.581652)
					(mid 51.560476 -4.962652)
					(end 51.941476 -5.343652)
				)
				(arc
					(start 52.805076 -5.343652)
					(mid 53.186076 -4.962652)
					(end 52.805076 -4.581652)
				)
			)
		)
	)
	(zone
		(layers "F.Cu" "B.Cu" "In1.Cu" "In2.Cu" "In3.Cu" "In4.Cu" "In5.Cu" "In6.Cu"
			"In7.Cu" "In8.Cu" "In9.Cu" "In10.Cu" "In11.Cu" "In12.Cu" "In13.Cu" "In14.Cu"
			"In15.Cu" "In16.Cu"
		)
		(hatch none 0.5)
		(connect_pads
			(clearance 0)
		)
		(min_thickness 0.25)
		(keepout
			(tracks not_allowed)
			(vias allowed)
			(pads allowed)
			(copperpour not_allowed)
			(footprints allowed)
		)
		(placement
			(enabled no)
			(sheetname "")
		)
		(fill
			(thermal_gap 0.5)
			(thermal_bridge_width 0.5)
			(island_removal_mode 0)
		)
		(polygon
			(pts
				(arc
					(start 109.149896 -217.878406)
					(mid 108.492036 -217.878406)
					(end 109.149896 -217.878406)
				)
			)
		)
	)
	(zone
		(layers "F.Cu" "B.Cu" "In1.Cu" "In2.Cu" "In3.Cu" "In4.Cu" "In5.Cu" "In6.Cu"
			"In7.Cu" "In8.Cu" "In9.Cu" "In10.Cu" "In11.Cu" "In12.Cu" "In13.Cu" "In14.Cu"
			"In15.Cu" "In16.Cu"
		)
		(hatch none 0.5)
		(connect_pads
			(clearance 0)
		)
		(min_thickness 0.25)
		(keepout
			(tracks not_allowed)
			(vias allowed)
			(pads allowed)
			(copperpour not_allowed)
			(footprints allowed)
		)
		(placement
			(enabled no)
			(sheetname "")
		)
		(fill
			(thermal_gap 0.5)
			(thermal_bridge_width 0.5)
			(island_removal_mode 0)
		)
		(polygon
			(pts
				(arc
					(start 368.788696 -285.759652)
					(mid 368.80838 -285.712242)
					(end 368.815112 -285.661354)
				)
				(arc
					(start 368.815112 -285.661354)
					(mid 368.757456 -285.52216)
					(end 368.618262 -285.464504)
				)
				(arc
					(start 368.618262 -285.464504)
					(mid 368.519831 -285.49092)
					(end 368.447828 -285.563056)
				)
				(arc
					(start 367.978182 -286.377126)
					(mid 367.958498 -286.424536)
					(end 367.951766 -286.475424)
				)
				(arc
					(start 367.951766 -286.475424)
					(mid 368.009422 -286.614618)
					(end 368.148616 -286.672274)
				)
				(arc
					(start 368.148616 -286.672274)
					(mid 368.247047 -286.645858)
					(end 368.31905 -286.573722)
				)
			)
		)
	)
	(zone
		(layers "F.Cu" "B.Cu" "In1.Cu" "In2.Cu" "In3.Cu" "In4.Cu" "In5.Cu" "In6.Cu"
			"In7.Cu" "In8.Cu" "In9.Cu" "In10.Cu" "In11.Cu" "In12.Cu" "In13.Cu" "In14.Cu"
			"In15.Cu" "In16.Cu"
		)
		(hatch none 0.5)
		(connect_pads
			(clearance 0)
		)
		(min_thickness 0.25)
		(keepout
			(tracks not_allowed)
			(vias allowed)
			(pads allowed)
			(copperpour not_allowed)
			(footprints allowed)
		)
		(placement
			(enabled no)
			(sheetname "")
		)
		(fill
			(thermal_gap 0.5)
			(thermal_bridge_width 0.5)
			(island_removal_mode 0)
		)
		(polygon
			(pts
				(arc
					(start 129.747518 -288.917126)
					(mid 130.405378 -288.917126)
					(end 129.747518 -288.917126)
				)
			)
		)
	)
	(zone
		(layers "F.Cu" "B.Cu" "In1.Cu" "In2.Cu" "In3.Cu" "In4.Cu" "In5.Cu" "In6.Cu"
			"In7.Cu" "In8.Cu" "In9.Cu" "In10.Cu" "In11.Cu" "In12.Cu" "In13.Cu" "In14.Cu"
			"In15.Cu" "In16.Cu"
		)
		(hatch none 0.5)
		(connect_pads
			(clearance 0)
		)
		(min_thickness 0.25)
		(keepout
			(tracks not_allowed)
			(vias allowed)
			(pads allowed)
			(copperpour not_allowed)
			(footprints allowed)
		)
		(placement
			(enabled no)
			(sheetname "")
		)
		(fill
			(thermal_gap 0.5)
			(thermal_bridge_width 0.5)
			(island_removal_mode 0)
		)
		(polygon
			(pts
				(arc
					(start 376.197622 -220.22181)
					(mid 376.125633 -220.149651)
					(end 376.027188 -220.123258)
				)
				(arc
					(start 376.027188 -220.123258)
					(mid 375.887994 -220.180914)
					(end 375.830338 -220.320108)
				)
				(arc
					(start 375.830338 -220.320108)
					(mid 375.837095 -220.370989)
					(end 375.856754 -220.418406)
				)
				(arc
					(start 376.3264 -221.232222)
					(mid 376.398389 -221.304381)
					(end 376.496834 -221.330774)
				)
				(arc
					(start 376.496834 -221.330774)
					(mid 376.636028 -221.273118)
					(end 376.693684 -221.133924)
				)
				(arc
					(start 376.693684 -221.133924)
					(mid 376.686927 -221.083043)
					(end 376.667268 -221.035626)
				)
			)
		)
	)
	(zone
		(layers "F.Cu" "B.Cu" "In1.Cu" "In2.Cu" "In3.Cu" "In4.Cu" "In5.Cu" "In6.Cu"
			"In7.Cu" "In8.Cu" "In9.Cu" "In10.Cu" "In11.Cu" "In12.Cu" "In13.Cu" "In14.Cu"
			"In15.Cu" "In16.Cu"
		)
		(hatch none 0.5)
		(connect_pads
			(clearance 0)
		)
		(min_thickness 0.25)
		(keepout
			(tracks not_allowed)
			(vias allowed)
			(pads allowed)
			(copperpour not_allowed)
			(footprints allowed)
		)
		(placement
			(enabled no)
			(sheetname "")
		)
		(fill
			(thermal_gap 0.5)
			(thermal_bridge_width 0.5)
			(island_removal_mode 0)
		)
		(polygon
			(pts
				(arc
					(start 122.618754 -220.22181)
					(mid 122.546765 -220.149651)
					(end 122.44832 -220.123258)
				)
				(arc
					(start 122.44832 -220.123258)
					(mid 122.309126 -220.180914)
					(end 122.25147 -220.320108)
				)
				(arc
					(start 122.25147 -220.320108)
					(mid 122.258227 -220.370989)
					(end 122.277886 -220.418406)
				)
				(arc
					(start 122.747532 -221.232222)
					(mid 122.819521 -221.304381)
					(end 122.917966 -221.330774)
				)
				(arc
					(start 122.917966 -221.330774)
					(mid 123.05716 -221.273118)
					(end 123.114816 -221.133924)
				)
				(arc
					(start 123.114816 -221.133924)
					(mid 123.108059 -221.083043)
					(end 123.0884 -221.035626)
				)
			)
		)
	)
	(zone
		(layers "F.Cu" "B.Cu" "In1.Cu" "In2.Cu" "In3.Cu" "In4.Cu" "In5.Cu" "In6.Cu"
			"In7.Cu" "In8.Cu" "In9.Cu" "In10.Cu" "In11.Cu" "In12.Cu" "In13.Cu" "In14.Cu"
			"In15.Cu" "In16.Cu"
		)
		(hatch none 0.5)
		(connect_pads
			(clearance 0)
		)
		(min_thickness 0.25)
		(keepout
			(tracks not_allowed)
			(vias allowed)
			(pads allowed)
			(copperpour not_allowed)
			(footprints allowed)
		)
		(placement
			(enabled no)
			(sheetname "")
		)
		(fill
			(thermal_gap 0.5)
			(thermal_bridge_width 0.5)
			(island_removal_mode 0)
		)
		(polygon
			(pts
				(arc
					(start 99.281742 -225.203258)
					(mid 98.623882 -225.203258)
					(end 99.281742 -225.203258)
				)
			)
		)
	)
	(zone
		(layers "F.Cu" "B.Cu" "In1.Cu" "In2.Cu" "In3.Cu" "In4.Cu" "In5.Cu" "In6.Cu"
			"In7.Cu" "In8.Cu" "In9.Cu" "In10.Cu" "In11.Cu" "In12.Cu" "In13.Cu" "In14.Cu"
			"In15.Cu" "In16.Cu"
		)
		(hatch none 0.5)
		(connect_pads
			(clearance 0)
		)
		(min_thickness 0.25)
		(keepout
			(tracks not_allowed)
			(vias allowed)
			(pads allowed)
			(copperpour not_allowed)
			(footprints allowed)
		)
		(placement
			(enabled no)
			(sheetname "")
		)
		(fill
			(thermal_gap 0.5)
			(thermal_bridge_width 0.5)
			(island_removal_mode 0)
		)
		(polygon
			(pts
				(arc
					(start 98.183446 -217.162634)
					(mid 98.20313 -217.115224)
					(end 98.209862 -217.064336)
				)
				(arc
					(start 98.209862 -217.064336)
					(mid 98.152206 -216.925142)
					(end 98.013012 -216.867486)
				)
				(arc
					(start 98.013012 -216.867486)
					(mid 97.914581 -216.893902)
					(end 97.842578 -216.966038)
				)
				(arc
					(start 97.372932 -217.780108)
					(mid 97.353248 -217.827518)
					(end 97.346516 -217.878406)
				)
				(arc
					(start 97.346516 -217.878406)
					(mid 97.404172 -218.0176)
					(end 97.543366 -218.075256)
				)
				(arc
					(start 97.543366 -218.075256)
					(mid 97.641797 -218.04884)
					(end 97.7138 -217.976704)
				)
			)
		)
	)
	(zone
		(layers "F.Cu" "B.Cu" "In1.Cu" "In2.Cu" "In3.Cu" "In4.Cu" "In5.Cu" "In6.Cu"
			"In7.Cu" "In8.Cu" "In9.Cu" "In10.Cu" "In11.Cu" "In12.Cu" "In13.Cu" "In14.Cu"
			"In15.Cu" "In16.Cu"
		)
		(hatch none 0.5)
		(connect_pads
			(clearance 0)
		)
		(min_thickness 0.25)
		(keepout
			(tracks not_allowed)
			(vias allowed)
			(pads allowed)
			(copperpour not_allowed)
			(footprints allowed)
		)
		(placement
			(enabled no)
			(sheetname "")
		)
		(fill
			(thermal_gap 0.5)
			(thermal_bridge_width 0.5)
			(island_removal_mode 0)
		)
		(polygon
			(pts
				(arc
					(start 120.738646 -223.67367)
					(mid 120.75833 -223.62626)
					(end 120.765062 -223.575372)
				)
				(arc
					(start 120.765062 -223.575372)
					(mid 120.707406 -223.436178)
					(end 120.568212 -223.378522)
				)
				(arc
					(start 120.568212 -223.378522)
					(mid 120.469781 -223.404938)
					(end 120.397778 -223.477074)
				)
				(arc
					(start 119.928132 -224.291144)
					(mid 119.908448 -224.338554)
					(end 119.901716 -224.389442)
				)
				(arc
					(start 119.901716 -224.389442)
					(mid 119.959372 -224.528636)
					(end 120.098566 -224.586292)
				)
				(arc
					(start 120.098566 -224.586292)
					(mid 120.196997 -224.559876)
					(end 120.269 -224.48774)
				)
			)
		)
	)
	(zone
		(layers "F.Cu" "B.Cu" "In1.Cu" "In2.Cu" "In3.Cu" "In4.Cu" "In5.Cu" "In6.Cu"
			"In7.Cu" "In8.Cu" "In9.Cu" "In10.Cu" "In11.Cu" "In12.Cu" "In13.Cu" "In14.Cu"
			"In15.Cu" "In16.Cu"
		)
		(hatch none 0.5)
		(connect_pads
			(clearance 0)
		)
		(min_thickness 0.25)
		(keepout
			(tracks not_allowed)
			(vias allowed)
			(pads allowed)
			(copperpour not_allowed)
			(footprints allowed)
		)
		(placement
			(enabled no)
			(sheetname "")
		)
		(fill
			(thermal_gap 0.5)
			(thermal_bridge_width 0.5)
			(island_removal_mode 0)
		)
		(polygon
			(pts
				(arc
					(start 121.367296 -224.389442)
					(mid 120.709436 -224.389442)
					(end 121.367296 -224.389442)
				)
			)
		)
	)
	(zone
		(layers "F.Cu" "B.Cu" "In1.Cu" "In2.Cu" "In3.Cu" "In4.Cu" "In5.Cu" "In6.Cu"
			"In7.Cu" "In8.Cu" "In9.Cu" "In10.Cu" "In11.Cu" "In12.Cu" "In13.Cu" "In14.Cu"
			"In15.Cu" "In16.Cu"
		)
		(hatch none 0.5)
		(connect_pads
			(clearance 0)
		)
		(min_thickness 0.25)
		(keepout
			(tracks not_allowed)
			(vias allowed)
			(pads allowed)
			(copperpour not_allowed)
			(footprints allowed)
		)
		(placement
			(enabled no)
			(sheetname "")
		)
		(fill
			(thermal_gap 0.5)
			(thermal_bridge_width 0.5)
			(island_removal_mode 0)
		)
		(polygon
			(pts
				(arc
					(start 350.271588 -66.963544)
					(mid 350.652588 -67.344544)
					(end 351.033588 -66.963544)
				)
				(arc
					(start 351.033588 -66.099944)
					(mid 350.652588 -65.718944)
					(end 350.271588 -66.099944)
				)
			)
		)
	)
	(zone
		(layers "F.Cu" "B.Cu" "In1.Cu" "In2.Cu" "In3.Cu" "In4.Cu" "In5.Cu" "In6.Cu"
			"In7.Cu" "In8.Cu" "In9.Cu" "In10.Cu" "In11.Cu" "In12.Cu" "In13.Cu" "In14.Cu"
			"In15.Cu" "In16.Cu"
		)
		(hatch none 0.5)
		(connect_pads
			(clearance 0)
		)
		(min_thickness 0.25)
		(keepout
			(tracks not_allowed)
			(vias allowed)
			(pads allowed)
			(copperpour not_allowed)
			(footprints allowed)
		)
		(placement
			(enabled no)
			(sheetname "")
		)
		(fill
			(thermal_gap 0.5)
			(thermal_bridge_width 0.5)
			(island_removal_mode 0)
		)
		(polygon
			(pts
				(arc
					(start 40.985694 -18.75536)
					(mid 40.604694 -19.13636)
					(end 40.985694 -19.51736)
				)
				(arc
					(start 41.849294 -19.51736)
					(mid 42.230294 -19.13636)
					(end 41.849294 -18.75536)
				)
			)
		)
	)
	(zone
		(layers "F.Cu" "B.Cu" "In1.Cu" "In2.Cu" "In3.Cu" "In4.Cu" "In5.Cu" "In6.Cu"
			"In7.Cu" "In8.Cu" "In9.Cu" "In10.Cu" "In11.Cu" "In12.Cu" "In13.Cu" "In14.Cu"
			"In15.Cu" "In16.Cu"
		)
		(hatch none 0.5)
		(connect_pads
			(clearance 0)
		)
		(min_thickness 0.25)
		(keepout
			(tracks not_allowed)
			(vias allowed)
			(pads allowed)
			(copperpour not_allowed)
			(footprints allowed)
		)
		(placement
			(enabled no)
			(sheetname "")
		)
		(fill
			(thermal_gap 0.5)
			(thermal_bridge_width 0.5)
			(island_removal_mode 0)
		)
		(polygon
			(pts
				(arc
					(start 379.17501 -225.203258)
					(mid 378.51715 -225.203258)
					(end 379.17501 -225.203258)
				)
			)
		)
	)
	(zone
		(layers "F.Cu" "B.Cu" "In1.Cu" "In2.Cu" "In3.Cu" "In4.Cu" "In5.Cu" "In6.Cu"
			"In7.Cu" "In8.Cu" "In9.Cu" "In10.Cu" "In11.Cu" "In12.Cu" "In13.Cu" "In14.Cu"
			"In15.Cu" "In16.Cu"
		)
		(hatch none 0.5)
		(connect_pads
			(clearance 0)
		)
		(min_thickness 0.25)
		(keepout
			(tracks not_allowed)
			(vias allowed)
			(pads allowed)
			(copperpour not_allowed)
			(footprints allowed)
		)
		(placement
			(enabled no)
			(sheetname "")
		)
		(fill
			(thermal_gap 0.5)
			(thermal_bridge_width 0.5)
			(island_removal_mode 0)
		)
		(polygon
			(pts
				(arc
					(start 347.473016 -281.39517)
					(mid 347.276166 -281.59202)
					(end 347.473016 -281.78887)
				)
				(arc
					(start 348.412816 -281.78887)
					(mid 348.609666 -281.59202)
					(end 348.412816 -281.39517)
				)
			)
		)
	)
	(zone
		(layers "F.Cu" "B.Cu" "In1.Cu" "In2.Cu" "In3.Cu" "In4.Cu" "In5.Cu" "In6.Cu"
			"In7.Cu" "In8.Cu" "In9.Cu" "In10.Cu" "In11.Cu" "In12.Cu" "In13.Cu" "In14.Cu"
			"In15.Cu" "In16.Cu"
		)
		(hatch none 0.5)
		(connect_pads
			(clearance 0)
		)
		(min_thickness 0.25)
		(keepout
			(tracks not_allowed)
			(vias allowed)
			(pads allowed)
			(copperpour not_allowed)
			(footprints allowed)
		)
		(placement
			(enabled no)
			(sheetname "")
		)
		(fill
			(thermal_gap 0.5)
			(thermal_bridge_width 0.5)
			(island_removal_mode 0)
		)
		(polygon
			(pts
				(arc
					(start 98.812096 -224.389442)
					(mid 98.154236 -224.389442)
					(end 98.812096 -224.389442)
				)
			)
		)
	)
	(zone
		(layers "F.Cu" "B.Cu" "In1.Cu" "In2.Cu" "In3.Cu" "In4.Cu" "In5.Cu" "In6.Cu"
			"In7.Cu" "In8.Cu" "In9.Cu" "In10.Cu" "In11.Cu" "In12.Cu" "In13.Cu" "In14.Cu"
			"In15.Cu" "In16.Cu"
		)
		(hatch none 0.5)
		(connect_pads
			(clearance 0)
		)
		(min_thickness 0.25)
		(keepout
			(tracks not_allowed)
			(vias allowed)
			(pads allowed)
			(copperpour not_allowed)
			(footprints allowed)
		)
		(placement
			(enabled no)
			(sheetname "")
		)
		(fill
			(thermal_gap 0.5)
			(thermal_bridge_width 0.5)
			(island_removal_mode 0)
		)
		(polygon
			(pts
				(arc
					(start 348.473268 -224.291144)
					(mid 348.401279 -224.218985)
					(end 348.302834 -224.192592)
				)
				(arc
					(start 348.302834 -224.192592)
					(mid 348.16364 -224.250248)
					(end 348.105984 -224.389442)
				)
				(arc
					(start 348.105984 -224.389442)
					(mid 348.112741 -224.440323)
					(end 348.1324 -224.48774)
				)
				(arc
					(start 348.602046 -225.301556)
					(mid 348.674035 -225.373715)
					(end 348.77248 -225.400108)
				)
				(arc
					(start 348.77248 -225.400108)
					(mid 348.911674 -225.342452)
					(end 348.96933 -225.203258)
				)
				(arc
					(start 348.96933 -225.203258)
					(mid 348.962573 -225.152377)
					(end 348.942914 -225.10496)
				)
			)
		)
	)
	(zone
		(layers "F.Cu" "B.Cu" "In1.Cu" "In2.Cu" "In3.Cu" "In4.Cu" "In5.Cu" "In6.Cu"
			"In7.Cu" "In8.Cu" "In9.Cu" "In10.Cu" "In11.Cu" "In12.Cu" "In13.Cu" "In14.Cu"
			"In15.Cu" "In16.Cu"
		)
		(hatch none 0.5)
		(connect_pads
			(clearance 0)
		)
		(min_thickness 0.25)
		(keepout
			(tracks not_allowed)
			(vias allowed)
			(pads allowed)
			(copperpour not_allowed)
			(footprints allowed)
		)
		(placement
			(enabled no)
			(sheetname "")
		)
		(fill
			(thermal_gap 0.5)
			(thermal_bridge_width 0.5)
			(island_removal_mode 0)
		)
		(polygon
			(pts
				(arc
					(start 341.53475 -285.563056)
					(mid 341.462761 -285.490897)
					(end 341.364316 -285.464504)
				)
				(arc
					(start 341.364316 -285.464504)
					(mid 341.225122 -285.52216)
					(end 341.167466 -285.661354)
				)
				(arc
					(start 341.167466 -285.661354)
					(mid 341.174223 -285.712235)
					(end 341.193882 -285.759652)
				)
				(arc
					(start 341.663782 -286.573722)
					(mid 341.735771 -286.645881)
					(end 341.834216 -286.672274)
				)
				(arc
					(start 341.834216 -286.672274)
					(mid 341.97341 -286.614618)
					(end 342.031066 -286.475424)
				)
				(arc
					(start 342.031066 -286.475424)
					(mid 342.024309 -286.424543)
					(end 342.00465 -286.377126)
				)
			)
		)
	)
	(zone
		(layers "F.Cu" "B.Cu" "In1.Cu" "In2.Cu" "In3.Cu" "In4.Cu" "In5.Cu" "In6.Cu"
			"In7.Cu" "In8.Cu" "In9.Cu" "In10.Cu" "In11.Cu" "In12.Cu" "In13.Cu" "In14.Cu"
			"In15.Cu" "In16.Cu"
		)
		(hatch none 0.5)
		(connect_pads
			(clearance 0)
		)
		(min_thickness 0.25)
		(keepout
			(tracks not_allowed)
			(vias allowed)
			(pads allowed)
			(copperpour not_allowed)
			(footprints allowed)
		)
		(placement
			(enabled no)
			(sheetname "")
		)
		(fill
			(thermal_gap 0.5)
			(thermal_bridge_width 0.5)
			(island_removal_mode 0)
		)
		(polygon
			(pts
				(arc
					(start 373.53621 -218.692222)
					(mid 372.87835 -218.692222)
					(end 373.53621 -218.692222)
				)
			)
		)
	)
	(zone
		(layers "F.Cu" "B.Cu" "In1.Cu" "In2.Cu" "In3.Cu" "In4.Cu" "In5.Cu" "In6.Cu"
			"In7.Cu" "In8.Cu" "In9.Cu" "In10.Cu" "In11.Cu" "In12.Cu" "In13.Cu" "In14.Cu"
			"In15.Cu" "In16.Cu"
		)
		(hatch none 0.5)
		(connect_pads
			(clearance 0)
		)
		(min_thickness 0.25)
		(keepout
			(tracks not_allowed)
			(vias allowed)
			(pads allowed)
			(copperpour not_allowed)
			(footprints allowed)
		)
		(placement
			(enabled no)
			(sheetname "")
		)
		(fill
			(thermal_gap 0.5)
			(thermal_bridge_width 0.5)
			(island_removal_mode 0)
		)
		(polygon
			(pts
				(arc
					(start 358.499664 -218.692222)
					(mid 357.841804 -218.692222)
					(end 358.499664 -218.692222)
				)
			)
		)
	)
	(zone
		(layers "F.Cu" "B.Cu" "In1.Cu" "In2.Cu" "In3.Cu" "In4.Cu" "In5.Cu" "In6.Cu"
			"In7.Cu" "In8.Cu" "In9.Cu" "In10.Cu" "In11.Cu" "In12.Cu" "In13.Cu" "In14.Cu"
			"In15.Cu" "In16.Cu"
		)
		(hatch none 0.5)
		(connect_pads
			(clearance 0)
		)
		(min_thickness 0.25)
		(keepout
			(tracks not_allowed)
			(vias allowed)
			(pads allowed)
			(copperpour not_allowed)
			(footprints allowed)
		)
		(placement
			(enabled no)
			(sheetname "")
		)
		(fill
			(thermal_gap 0.5)
			(thermal_bridge_width 0.5)
			(island_removal_mode 0)
		)
		(polygon
			(pts
				(arc
					(start 343.243916 -280.581354)
					(mid 343.047066 -280.778204)
					(end 343.243916 -280.975054)
				)
				(arc
					(start 344.183716 -280.975054)
					(mid 344.380566 -280.778204)
					(end 344.183716 -280.581354)
				)
			)
		)
	)
	(zone
		(layers "F.Cu" "B.Cu" "In1.Cu" "In2.Cu" "In3.Cu" "In4.Cu" "In5.Cu" "In6.Cu"
			"In7.Cu" "In8.Cu" "In9.Cu" "In10.Cu" "In11.Cu" "In12.Cu" "In13.Cu" "In14.Cu"
			"In15.Cu" "In16.Cu"
		)
		(hatch none 0.5)
		(connect_pads
			(clearance 0)
		)
		(min_thickness 0.25)
		(keepout
			(tracks not_allowed)
			(vias allowed)
			(pads allowed)
			(copperpour not_allowed)
			(footprints allowed)
		)
		(placement
			(enabled no)
			(sheetname "")
		)
		(fill
			(thermal_gap 0.5)
			(thermal_bridge_width 0.5)
			(island_removal_mode 0)
		)
		(polygon
			(pts
				(arc
					(start 349.99295 -279.051766)
					(mid 349.920961 -278.979607)
					(end 349.822516 -278.953214)
				)
				(arc
					(start 349.822516 -278.953214)
					(mid 349.683322 -279.01087)
					(end 349.625666 -279.150064)
				)
				(arc
					(start 349.625666 -279.150064)
					(mid 349.632423 -279.200945)
					(end 349.652082 -279.248362)
				)
				(arc
					(start 350.121982 -280.062432)
					(mid 350.193971 -280.134591)
					(end 350.292416 -280.160984)
				)
				(arc
					(start 350.292416 -280.160984)
					(mid 350.43161 -280.103328)
					(end 350.489266 -279.964134)
				)
				(arc
					(start 350.489266 -279.964134)
					(mid 350.482509 -279.913253)
					(end 350.46285 -279.865836)
				)
			)
		)
	)
	(zone
		(layers "F.Cu" "B.Cu" "In1.Cu" "In2.Cu" "In3.Cu" "In4.Cu" "In5.Cu" "In6.Cu"
			"In7.Cu" "In8.Cu" "In9.Cu" "In10.Cu" "In11.Cu" "In12.Cu" "In13.Cu" "In14.Cu"
			"In15.Cu" "In16.Cu"
		)
		(hatch none 0.5)
		(connect_pads
			(clearance 0)
		)
		(min_thickness 0.25)
		(keepout
			(tracks not_allowed)
			(vias allowed)
			(pads allowed)
			(copperpour not_allowed)
			(footprints allowed)
		)
		(placement
			(enabled no)
			(sheetname "")
		)
		(fill
			(thermal_gap 0.5)
			(thermal_bridge_width 0.5)
			(island_removal_mode 0)
		)
		(polygon
			(pts
				(arc
					(start 342.085168 -409.649168)
					(mid 341.704168 -410.030168)
					(end 342.085168 -410.411168)
				)
				(arc
					(start 342.948768 -410.411168)
					(mid 343.329768 -410.030168)
					(end 342.948768 -409.649168)
				)
			)
		)
	)
	(zone
		(layers "F.Cu" "B.Cu" "In1.Cu" "In2.Cu" "In3.Cu" "In4.Cu" "In5.Cu" "In6.Cu"
			"In7.Cu" "In8.Cu" "In9.Cu" "In10.Cu" "In11.Cu" "In12.Cu" "In13.Cu" "In14.Cu"
			"In15.Cu" "In16.Cu"
		)
		(hatch none 0.5)
		(connect_pads
			(clearance 0)
		)
		(min_thickness 0.25)
		(keepout
			(tracks not_allowed)
			(vias allowed)
			(pads allowed)
			(copperpour not_allowed)
			(footprints allowed)
		)
		(placement
			(enabled no)
			(sheetname "")
		)
		(fill
			(thermal_gap 0.5)
			(thermal_bridge_width 0.5)
			(island_removal_mode 0)
		)
		(polygon
			(pts
				(arc
					(start 402.05533 -400.477228)
					(mid 401.67433 -400.858228)
					(end 402.05533 -401.239228)
				)
				(arc
					(start 402.91893 -401.239228)
					(mid 403.29993 -400.858228)
					(end 402.91893 -400.477228)
				)
			)
		)
	)
	(zone
		(layers "F.Cu" "B.Cu" "In1.Cu" "In2.Cu" "In3.Cu" "In4.Cu" "In5.Cu" "In6.Cu"
			"In7.Cu" "In8.Cu" "In9.Cu" "In10.Cu" "In11.Cu" "In12.Cu" "In13.Cu" "In14.Cu"
			"In15.Cu" "In16.Cu"
		)
		(hatch none 0.5)
		(connect_pads
			(clearance 0)
		)
		(min_thickness 0.25)
		(keepout
			(tracks not_allowed)
			(vias allowed)
			(pads allowed)
			(copperpour not_allowed)
			(footprints allowed)
		)
		(placement
			(enabled no)
			(sheetname "")
		)
		(fill
			(thermal_gap 0.5)
			(thermal_bridge_width 0.5)
			(island_removal_mode 0)
		)
		(polygon
			(pts
				(arc
					(start 358.969564 -217.878406)
					(mid 358.311704 -217.878406)
					(end 358.969564 -217.878406)
				)
			)
		)
	)
	(zone
		(layers "F.Cu" "B.Cu" "In1.Cu" "In2.Cu" "In3.Cu" "In4.Cu" "In5.Cu" "In6.Cu"
			"In7.Cu" "In8.Cu" "In9.Cu" "In10.Cu" "In11.Cu" "In12.Cu" "In13.Cu" "In14.Cu"
			"In15.Cu" "In16.Cu"
		)
		(hatch none 0.5)
		(connect_pads
			(clearance 0)
		)
		(min_thickness 0.25)
		(keepout
			(tracks not_allowed)
			(vias allowed)
			(pads allowed)
			(copperpour not_allowed)
			(footprints allowed)
		)
		(placement
			(enabled no)
			(sheetname "")
		)
		(fill
			(thermal_gap 0.5)
			(thermal_bridge_width 0.5)
			(island_removal_mode 0)
		)
		(polygon
			(pts
				(arc
					(start 261.856982 2.491994)
					(mid 262.237982 2.110994)
					(end 262.618982 2.491994)
				)
				(arc
					(start 262.618982 3.355594)
					(mid 262.237982 3.736594)
					(end 261.856982 3.355594)
				)
			)
		)
	)
	(zone
		(layers "F.Cu" "B.Cu" "In1.Cu" "In2.Cu" "In3.Cu" "In4.Cu" "In5.Cu" "In6.Cu"
			"In7.Cu" "In8.Cu" "In9.Cu" "In10.Cu" "In11.Cu" "In12.Cu" "In13.Cu" "In14.Cu"
			"In15.Cu" "In16.Cu"
		)
		(hatch none 0.5)
		(connect_pads
			(clearance 0)
		)
		(min_thickness 0.25)
		(keepout
			(tracks not_allowed)
			(vias allowed)
			(pads allowed)
			(copperpour not_allowed)
			(footprints allowed)
		)
		(placement
			(enabled no)
			(sheetname "")
		)
		(fill
			(thermal_gap 0.5)
			(thermal_bridge_width 0.5)
			(island_removal_mode 0)
		)
		(polygon
			(pts
				(arc
					(start 345.452192 -282.405836)
					(mid 344.794332 -282.405836)
					(end 345.452192 -282.405836)
				)
			)
		)
	)
	(zone
		(layers "F.Cu" "B.Cu" "In1.Cu" "In2.Cu" "In3.Cu" "In4.Cu" "In5.Cu" "In6.Cu"
			"In7.Cu" "In8.Cu" "In9.Cu" "In10.Cu" "In11.Cu" "In12.Cu" "In13.Cu" "In14.Cu"
			"In15.Cu" "In16.Cu"
		)
		(hatch none 0.5)
		(connect_pads
			(clearance 0)
		)
		(min_thickness 0.25)
		(keepout
			(tracks not_allowed)
			(vias allowed)
			(pads allowed)
			(copperpour not_allowed)
			(footprints allowed)
		)
		(placement
			(enabled no)
			(sheetname "")
		)
		(fill
			(thermal_gap 0.5)
			(thermal_bridge_width 0.5)
			(island_removal_mode 0)
		)
		(polygon
			(pts
				(arc
					(start 179.39258 -51.618134)
					(mid 179.01158 -51.237134)
					(end 178.63058 -51.618134)
				)
				(arc
					(start 178.63058 -52.481734)
					(mid 179.01158 -52.862734)
					(end 179.39258 -52.481734)
				)
			)
		)
	)
	(zone
		(layers "F.Cu" "B.Cu" "In1.Cu" "In2.Cu" "In3.Cu" "In4.Cu" "In5.Cu" "In6.Cu"
			"In7.Cu" "In8.Cu" "In9.Cu" "In10.Cu" "In11.Cu" "In12.Cu" "In13.Cu" "In14.Cu"
			"In15.Cu" "In16.Cu"
		)
		(hatch none 0.5)
		(connect_pads
			(clearance 0)
		)
		(min_thickness 0.25)
		(keepout
			(tracks not_allowed)
			(vias allowed)
			(pads allowed)
			(copperpour not_allowed)
			(footprints allowed)
		)
		(placement
			(enabled no)
			(sheetname "")
		)
		(fill
			(thermal_gap 0.5)
			(thermal_bridge_width 0.5)
			(island_removal_mode 0)
		)
		(polygon
			(pts
				(arc
					(start 120.268492 -214.720932)
					(mid 120.288176 -214.673522)
					(end 120.294908 -214.622634)
				)
				(arc
					(start 120.294908 -214.622634)
					(mid 120.237252 -214.48344)
					(end 120.098058 -214.425784)
				)
				(arc
					(start 120.098058 -214.425784)
					(mid 119.999627 -214.4522)
					(end 119.927624 -214.524336)
				)
				(arc
					(start 119.457978 -215.338406)
					(mid 119.438294 -215.385816)
					(end 119.431562 -215.436704)
				)
				(arc
					(start 119.431562 -215.436704)
					(mid 119.489218 -215.575898)
					(end 119.628412 -215.633554)
				)
				(arc
					(start 119.628412 -215.633554)
					(mid 119.726843 -215.607138)
					(end 119.798846 -215.535002)
				)
			)
		)
	)
	(zone
		(layers "F.Cu" "B.Cu" "In1.Cu" "In2.Cu" "In3.Cu" "In4.Cu" "In5.Cu" "In6.Cu"
			"In7.Cu" "In8.Cu" "In9.Cu" "In10.Cu" "In11.Cu" "In12.Cu" "In13.Cu" "In14.Cu"
			"In15.Cu" "In16.Cu"
		)
		(hatch none 0.5)
		(connect_pads
			(clearance 0)
		)
		(min_thickness 0.25)
		(keepout
			(tracks not_allowed)
			(vias allowed)
			(pads allowed)
			(copperpour not_allowed)
			(footprints allowed)
		)
		(placement
			(enabled no)
			(sheetname "")
		)
		(fill
			(thermal_gap 0.5)
			(thermal_bridge_width 0.5)
			(island_removal_mode 0)
		)
		(polygon
			(pts
				(arc
					(start 99.861878 -281.59202)
					(mid 99.204018 -281.59202)
					(end 99.861878 -281.59202)
				)
			)
		)
	)
	(zone
		(layers "F.Cu" "B.Cu" "In1.Cu" "In2.Cu" "In3.Cu" "In4.Cu" "In5.Cu" "In6.Cu"
			"In7.Cu" "In8.Cu" "In9.Cu" "In10.Cu" "In11.Cu" "In12.Cu" "In13.Cu" "In14.Cu"
			"In15.Cu" "In16.Cu"
		)
		(hatch none 0.5)
		(connect_pads
			(clearance 0)
		)
		(min_thickness 0.25)
		(keepout
			(tracks not_allowed)
			(vias allowed)
			(pads allowed)
			(copperpour not_allowed)
			(footprints allowed)
		)
		(placement
			(enabled no)
			(sheetname "")
		)
		(fill
			(thermal_gap 0.5)
			(thermal_bridge_width 0.5)
			(island_removal_mode 0)
		)
		(polygon
			(pts
				(arc
					(start 84.738718 -403.502876)
					(mid 84.357718 -403.883876)
					(end 84.738718 -404.264876)
				)
				(arc
					(start 85.602318 -404.264876)
					(mid 85.983318 -403.883876)
					(end 85.602318 -403.502876)
				)
			)
		)
	)
	(zone
		(layers "F.Cu" "B.Cu" "In1.Cu" "In2.Cu" "In3.Cu" "In4.Cu" "In5.Cu" "In6.Cu"
			"In7.Cu" "In8.Cu" "In9.Cu" "In10.Cu" "In11.Cu" "In12.Cu" "In13.Cu" "In14.Cu"
			"In15.Cu" "In16.Cu"
		)
		(hatch none 0.5)
		(connect_pads
			(clearance 0)
		)
		(min_thickness 0.25)
		(keepout
			(tracks not_allowed)
			(vias allowed)
			(pads allowed)
			(copperpour not_allowed)
			(footprints allowed)
		)
		(placement
			(enabled no)
			(sheetname "")
		)
		(fill
			(thermal_gap 0.5)
			(thermal_bridge_width 0.5)
			(island_removal_mode 0)
		)
		(polygon
			(pts
				(arc
					(start 94.974664 -285.661354)
					(mid 95.632524 -285.661354)
					(end 94.974664 -285.661354)
				)
			)
		)
	)
	(zone
		(layers "F.Cu" "B.Cu" "In1.Cu" "In2.Cu" "In3.Cu" "In4.Cu" "In5.Cu" "In6.Cu"
			"In7.Cu" "In8.Cu" "In9.Cu" "In10.Cu" "In11.Cu" "In12.Cu" "In13.Cu" "In14.Cu"
			"In15.Cu" "In16.Cu"
		)
		(hatch none 0.5)
		(connect_pads
			(clearance 0)
		)
		(min_thickness 0.25)
		(keepout
			(tracks not_allowed)
			(vias allowed)
			(pads allowed)
			(copperpour not_allowed)
			(footprints allowed)
		)
		(placement
			(enabled no)
			(sheetname "")
		)
		(fill
			(thermal_gap 0.5)
			(thermal_bridge_width 0.5)
			(island_removal_mode 0)
		)
		(polygon
			(pts
				(arc
					(start 99.751896 -224.389442)
					(mid 99.094036 -224.389442)
					(end 99.751896 -224.389442)
				)
			)
		)
	)
	(zone
		(layers "F.Cu" "B.Cu" "In1.Cu" "In2.Cu" "In3.Cu" "In4.Cu" "In5.Cu" "In6.Cu"
			"In7.Cu" "In8.Cu" "In9.Cu" "In10.Cu" "In11.Cu" "In12.Cu" "In13.Cu" "In14.Cu"
			"In15.Cu" "In16.Cu"
		)
		(hatch none 0.5)
		(connect_pads
			(clearance 0)
		)
		(min_thickness 0.25)
		(keepout
			(tracks not_allowed)
			(vias allowed)
			(pads allowed)
			(copperpour not_allowed)
			(footprints allowed)
		)
		(placement
			(enabled no)
			(sheetname "")
		)
		(fill
			(thermal_gap 0.5)
			(thermal_bridge_width 0.5)
			(island_removal_mode 0)
		)
		(polygon
			(pts
				(arc
					(start 350.151192 -282.405836)
					(mid 349.493332 -282.405836)
					(end 350.151192 -282.405836)
				)
			)
		)
	)
	(zone
		(layers "F.Cu" "B.Cu" "In1.Cu" "In2.Cu" "In3.Cu" "In4.Cu" "In5.Cu" "In6.Cu"
			"In7.Cu" "In8.Cu" "In9.Cu" "In10.Cu" "In11.Cu" "In12.Cu" "In13.Cu" "In14.Cu"
			"In15.Cu" "In16.Cu"
		)
		(hatch none 0.5)
		(connect_pads
			(clearance 0)
		)
		(min_thickness 0.25)
		(keepout
			(tracks not_allowed)
			(vias allowed)
			(pads allowed)
			(copperpour not_allowed)
			(footprints allowed)
		)
		(placement
			(enabled no)
			(sheetname "")
		)
		(fill
			(thermal_gap 0.5)
			(thermal_bridge_width 0.5)
			(island_removal_mode 0)
		)
		(polygon
			(pts
				(arc
					(start 351.274888 -409.649168)
					(mid 350.893888 -410.030168)
					(end 351.274888 -410.411168)
				)
				(arc
					(start 352.138488 -410.411168)
					(mid 352.519488 -410.030168)
					(end 352.138488 -409.649168)
				)
			)
		)
	)
	(zone
		(layers "F.Cu" "B.Cu" "In1.Cu" "In2.Cu" "In3.Cu" "In4.Cu" "In5.Cu" "In6.Cu"
			"In7.Cu" "In8.Cu" "In9.Cu" "In10.Cu" "In11.Cu" "In12.Cu" "In13.Cu" "In14.Cu"
			"In15.Cu" "In16.Cu"
		)
		(hatch none 0.5)
		(connect_pads
			(clearance 0)
		)
		(min_thickness 0.25)
		(keepout
			(tracks not_allowed)
			(vias allowed)
			(pads allowed)
			(copperpour not_allowed)
			(footprints allowed)
		)
		(placement
			(enabled no)
			(sheetname "")
		)
		(fill
			(thermal_gap 0.5)
			(thermal_bridge_width 0.5)
			(island_removal_mode 0)
		)
		(polygon
			(pts
				(arc
					(start 408.18181 -403.502876)
					(mid 407.80081 -403.883876)
					(end 408.18181 -404.264876)
				)
				(arc
					(start 409.04541 -404.264876)
					(mid 409.42641 -403.883876)
					(end 409.04541 -403.502876)
				)
			)
		)
	)
	(zone
		(layers "F.Cu" "B.Cu" "In1.Cu" "In2.Cu" "In3.Cu" "In4.Cu" "In5.Cu" "In6.Cu"
			"In7.Cu" "In8.Cu" "In9.Cu" "In10.Cu" "In11.Cu" "In12.Cu" "In13.Cu" "In14.Cu"
			"In15.Cu" "In16.Cu"
		)
		(hatch none 0.5)
		(connect_pads
			(clearance 0)
		)
		(min_thickness 0.25)
		(keepout
			(tracks not_allowed)
			(vias allowed)
			(pads allowed)
			(copperpour not_allowed)
			(footprints allowed)
		)
		(placement
			(enabled no)
			(sheetname "")
		)
		(fill
			(thermal_gap 0.5)
			(thermal_bridge_width 0.5)
			(island_removal_mode 0)
		)
		(polygon
			(pts
				(arc
					(start 378.076714 -223.67367)
					(mid 378.096398 -223.62626)
					(end 378.10313 -223.575372)
				)
				(arc
					(start 378.10313 -223.575372)
					(mid 378.045474 -223.436178)
					(end 377.90628 -223.378522)
				)
				(arc
					(start 377.90628 -223.378522)
					(mid 377.807849 -223.404938)
					(end 377.735846 -223.477074)
				)
				(arc
					(start 377.2662 -224.291144)
					(mid 377.246516 -224.338554)
					(end 377.239784 -224.389442)
				)
				(arc
					(start 377.239784 -224.389442)
					(mid 377.29744 -224.528636)
					(end 377.436634 -224.586292)
				)
				(arc
					(start 377.436634 -224.586292)
					(mid 377.535065 -224.559876)
					(end 377.607068 -224.48774)
				)
			)
		)
	)
	(zone
		(layers "F.Cu" "B.Cu" "In1.Cu" "In2.Cu" "In3.Cu" "In4.Cu" "In5.Cu" "In6.Cu"
			"In7.Cu" "In8.Cu" "In9.Cu" "In10.Cu" "In11.Cu" "In12.Cu" "In13.Cu" "In14.Cu"
			"In15.Cu" "In16.Cu"
		)
		(hatch none 0.5)
		(connect_pads
			(clearance 0)
		)
		(min_thickness 0.25)
		(keepout
			(tracks not_allowed)
			(vias allowed)
			(pads allowed)
			(copperpour not_allowed)
			(footprints allowed)
		)
		(placement
			(enabled no)
			(sheetname "")
		)
		(fill
			(thermal_gap 0.5)
			(thermal_bridge_width 0.5)
			(island_removal_mode 0)
		)
		(polygon
			(pts
				(arc
					(start 354.74021 -225.203258)
					(mid 354.08235 -225.203258)
					(end 354.74021 -225.203258)
				)
			)
		)
	)
	(zone
		(layers "F.Cu" "B.Cu" "In1.Cu" "In2.Cu" "In3.Cu" "In4.Cu" "In5.Cu" "In6.Cu"
			"In7.Cu" "In8.Cu" "In9.Cu" "In10.Cu" "In11.Cu" "In12.Cu" "In13.Cu" "In14.Cu"
			"In15.Cu" "In16.Cu"
		)
		(hatch none 0.5)
		(connect_pads
			(clearance 0)
		)
		(min_thickness 0.25)
		(keepout
			(tracks not_allowed)
			(vias allowed)
			(pads allowed)
			(copperpour not_allowed)
			(footprints allowed)
		)
		(placement
			(enabled no)
			(sheetname "")
		)
		(fill
			(thermal_gap 0.5)
			(thermal_bridge_width 0.5)
			(island_removal_mode 0)
		)
		(polygon
			(pts
				(arc
					(start 212.979254 -2.5908)
					(mid 213.360254 -2.9718)
					(end 213.741254 -2.5908)
				)
				(arc
					(start 213.741254 -1.7272)
					(mid 213.360254 -1.3462)
					(end 212.979254 -1.7272)
				)
			)
		)
	)
	(zone
		(layers "F.Cu" "B.Cu" "In1.Cu" "In2.Cu" "In3.Cu" "In4.Cu" "In5.Cu" "In6.Cu"
			"In7.Cu" "In8.Cu" "In9.Cu" "In10.Cu" "In11.Cu" "In12.Cu" "In13.Cu" "In14.Cu"
			"In15.Cu" "In16.Cu"
		)
		(hatch none 0.5)
		(connect_pads
			(clearance 0)
		)
		(min_thickness 0.25)
		(keepout
			(tracks not_allowed)
			(vias allowed)
			(pads allowed)
			(copperpour not_allowed)
			(footprints allowed)
		)
		(placement
			(enabled no)
			(sheetname "")
		)
		(fill
			(thermal_gap 0.5)
			(thermal_bridge_width 0.5)
			(island_removal_mode 0)
		)
		(polygon
			(pts
				(arc
					(start 415.65449 -409.649168)
					(mid 415.27349 -410.030168)
					(end 415.65449 -410.411168)
				)
				(arc
					(start 416.51809 -410.411168)
					(mid 416.89909 -410.030168)
					(end 416.51809 -409.649168)
				)
			)
		)
	)
	(zone
		(layers "F.Cu" "B.Cu" "In1.Cu" "In2.Cu" "In3.Cu" "In4.Cu" "In5.Cu" "In6.Cu"
			"In7.Cu" "In8.Cu" "In9.Cu" "In10.Cu" "In11.Cu" "In12.Cu" "In13.Cu" "In14.Cu"
			"In15.Cu" "In16.Cu"
		)
		(hatch none 0.5)
		(connect_pads
			(clearance 0)
		)
		(min_thickness 0.25)
		(keepout
			(tracks not_allowed)
			(vias allowed)
			(pads allowed)
			(copperpour not_allowed)
			(footprints allowed)
		)
		(placement
			(enabled no)
			(sheetname "")
		)
		(fill
			(thermal_gap 0.5)
			(thermal_bridge_width 0.5)
			(island_removal_mode 0)
		)
		(polygon
			(pts
				(arc
					(start 342.356948 -213.646766)
					(mid 342.28924 -213.574915)
					(end 342.194134 -213.548468)
				)
				(arc
					(start 342.194134 -213.548468)
					(mid 342.06392 -213.602404)
					(end 342.009984 -213.732618)
				)
				(arc
					(start 342.009984 -213.732618)
					(mid 342.015435 -213.776839)
					(end 342.03132 -213.81847)
				)
				(arc
					(start 342.500712 -214.708486)
					(mid 342.56842 -214.780337)
					(end 342.663526 -214.806784)
				)
				(arc
					(start 342.663526 -214.806784)
					(mid 342.79374 -214.752848)
					(end 342.847676 -214.622634)
				)
				(arc
					(start 342.847676 -214.622634)
					(mid 342.842225 -214.578413)
					(end 342.82634 -214.536782)
				)
			)
		)
	)
	(zone
		(layers "F.Cu" "B.Cu" "In1.Cu" "In2.Cu" "In3.Cu" "In4.Cu" "In5.Cu" "In6.Cu"
			"In7.Cu" "In8.Cu" "In9.Cu" "In10.Cu" "In11.Cu" "In12.Cu" "In13.Cu" "In14.Cu"
			"In15.Cu" "In16.Cu"
		)
		(hatch none 0.5)
		(connect_pads
			(clearance 0)
		)
		(min_thickness 0.25)
		(keepout
			(tracks not_allowed)
			(vias allowed)
			(pads allowed)
			(copperpour not_allowed)
			(footprints allowed)
		)
		(placement
			(enabled no)
			(sheetname "")
		)
		(fill
			(thermal_gap 0.5)
			(thermal_bridge_width 0.5)
			(island_removal_mode 0)
		)
		(polygon
			(pts
				(arc
					(start 108.131864 -277.522432)
					(mid 108.789724 -277.522432)
					(end 108.131864 -277.522432)
				)
			)
		)
	)
	(zone
		(layers "F.Cu" "B.Cu" "In1.Cu" "In2.Cu" "In3.Cu" "In4.Cu" "In5.Cu" "In6.Cu"
			"In7.Cu" "In8.Cu" "In9.Cu" "In10.Cu" "In11.Cu" "In12.Cu" "In13.Cu" "In14.Cu"
			"In15.Cu" "In16.Cu"
		)
		(hatch none 0.5)
		(connect_pads
			(clearance 0)
		)
		(min_thickness 0.25)
		(keepout
			(tracks not_allowed)
			(vias allowed)
			(pads allowed)
			(copperpour not_allowed)
			(footprints allowed)
		)
		(placement
			(enabled no)
			(sheetname "")
		)
		(fill
			(thermal_gap 0.5)
			(thermal_bridge_width 0.5)
			(island_removal_mode 0)
		)
		(polygon
			(pts
				(arc
					(start 322.359528 -403.502876)
					(mid 321.978528 -403.883876)
					(end 322.359528 -404.264876)
				)
				(arc
					(start 323.223128 -404.264876)
					(mid 323.604128 -403.883876)
					(end 323.223128 -403.502876)
				)
			)
		)
	)
	(zone
		(layers "F.Cu" "B.Cu" "In1.Cu" "In2.Cu" "In3.Cu" "In4.Cu" "In5.Cu" "In6.Cu"
			"In7.Cu" "In8.Cu" "In9.Cu" "In10.Cu" "In11.Cu" "In12.Cu" "In13.Cu" "In14.Cu"
			"In15.Cu" "In16.Cu"
		)
		(hatch none 0.5)
		(connect_pads
			(clearance 0)
		)
		(min_thickness 0.25)
		(keepout
			(tracks not_allowed)
			(vias allowed)
			(pads allowed)
			(copperpour not_allowed)
			(footprints allowed)
		)
		(placement
			(enabled no)
			(sheetname "")
		)
		(fill
			(thermal_gap 0.5)
			(thermal_bridge_width 0.5)
			(island_removal_mode 0)
		)
		(polygon
			(pts
				(arc
					(start 99.39782 -403.01037)
					(mid 99.77882 -402.62937)
					(end 99.39782 -402.24837)
				)
				(arc
					(start 98.53422 -402.24837)
					(mid 98.15322 -402.62937)
					(end 98.53422 -403.01037)
				)
			)
		)
	)
	(zone
		(layers "F.Cu" "B.Cu" "In1.Cu" "In2.Cu" "In3.Cu" "In4.Cu" "In5.Cu" "In6.Cu"
			"In7.Cu" "In8.Cu" "In9.Cu" "In10.Cu" "In11.Cu" "In12.Cu" "In13.Cu" "In14.Cu"
			"In15.Cu" "In16.Cu"
		)
		(hatch none 0.5)
		(connect_pads
			(clearance 0)
		)
		(min_thickness 0.25)
		(keepout
			(tracks not_allowed)
			(vias allowed)
			(pads allowed)
			(copperpour not_allowed)
			(footprints allowed)
		)
		(placement
			(enabled no)
			(sheetname "")
		)
		(fill
			(thermal_gap 0.5)
			(thermal_bridge_width 0.5)
			(island_removal_mode 0)
		)
		(polygon
			(pts
				(arc
					(start 320.642488 -406.62352)
					(mid 320.261488 -407.00452)
					(end 320.642488 -407.38552)
				)
				(arc
					(start 321.506088 -407.38552)
					(mid 321.887088 -407.00452)
					(end 321.506088 -406.62352)
				)
			)
		)
	)
	(zone
		(layers "F.Cu" "B.Cu" "In1.Cu" "In2.Cu" "In3.Cu" "In4.Cu" "In5.Cu" "In6.Cu"
			"In7.Cu" "In8.Cu" "In9.Cu" "In10.Cu" "In11.Cu" "In12.Cu" "In13.Cu" "In14.Cu"
			"In15.Cu" "In16.Cu"
		)
		(hatch none 0.5)
		(connect_pads
			(clearance 0)
		)
		(min_thickness 0.25)
		(keepout
			(tracks not_allowed)
			(vias allowed)
			(pads allowed)
			(copperpour not_allowed)
			(footprints allowed)
		)
		(placement
			(enabled no)
			(sheetname "")
		)
		(fill
			(thermal_gap 0.5)
			(thermal_bridge_width 0.5)
			(island_removal_mode 0)
		)
		(polygon
			(pts
				(arc
					(start 368.477292 -289.807142)
					(mid 367.819432 -289.807142)
					(end 368.477292 -289.807142)
				)
			)
		)
	)
	(zone
		(layers "F.Cu" "B.Cu" "In1.Cu" "In2.Cu" "In3.Cu" "In4.Cu" "In5.Cu" "In6.Cu"
			"In7.Cu" "In8.Cu" "In9.Cu" "In10.Cu" "In11.Cu" "In12.Cu" "In13.Cu" "In14.Cu"
			"In15.Cu" "In16.Cu"
		)
		(hatch none 0.5)
		(connect_pads
			(clearance 0)
		)
		(min_thickness 0.25)
		(keepout
			(tracks not_allowed)
			(vias allowed)
			(pads allowed)
			(copperpour not_allowed)
			(footprints allowed)
		)
		(placement
			(enabled no)
			(sheetname "")
		)
		(fill
			(thermal_gap 0.5)
			(thermal_bridge_width 0.5)
			(island_removal_mode 0)
		)
		(polygon
			(pts
				(arc
					(start 350.98101 -225.203258)
					(mid 350.32315 -225.203258)
					(end 350.98101 -225.203258)
				)
			)
		)
	)
	(zone
		(layers "F.Cu" "B.Cu" "In1.Cu" "In2.Cu" "In3.Cu" "In4.Cu" "In5.Cu" "In6.Cu"
			"In7.Cu" "In8.Cu" "In9.Cu" "In10.Cu" "In11.Cu" "In12.Cu" "In13.Cu" "In14.Cu"
			"In15.Cu" "In16.Cu"
		)
		(hatch none 0.5)
		(connect_pads
			(clearance 0)
		)
		(min_thickness 0.25)
		(keepout
			(tracks not_allowed)
			(vias allowed)
			(pads allowed)
			(copperpour not_allowed)
			(footprints allowed)
		)
		(placement
			(enabled no)
			(sheetname "")
		)
		(fill
			(thermal_gap 0.5)
			(thermal_bridge_width 0.5)
			(island_removal_mode 0)
		)
		(polygon
			(pts
				(arc
					(start 337.82381 -215.436704)
					(mid 337.16595 -215.436704)
					(end 337.82381 -215.436704)
				)
			)
		)
	)
	(zone
		(layers "F.Cu" "B.Cu" "In1.Cu" "In2.Cu" "In3.Cu" "In4.Cu" "In5.Cu" "In6.Cu"
			"In7.Cu" "In8.Cu" "In9.Cu" "In10.Cu" "In11.Cu" "In12.Cu" "In13.Cu" "In14.Cu"
			"In15.Cu" "In16.Cu"
		)
		(hatch none 0.5)
		(connect_pads
			(clearance 0)
		)
		(min_thickness 0.25)
		(keepout
			(tracks not_allowed)
			(vias allowed)
			(pads allowed)
			(copperpour not_allowed)
			(footprints allowed)
		)
		(placement
			(enabled no)
			(sheetname "")
		)
		(fill
			(thermal_gap 0.5)
			(thermal_bridge_width 0.5)
			(island_removal_mode 0)
		)
		(polygon
			(pts
				(arc
					(start 337.354164 -217.878406)
					(mid 336.696304 -217.878406)
					(end 337.354164 -217.878406)
				)
			)
		)
	)
	(zone
		(layers "F.Cu" "B.Cu" "In1.Cu" "In2.Cu" "In3.Cu" "In4.Cu" "In5.Cu" "In6.Cu"
			"In7.Cu" "In8.Cu" "In9.Cu" "In10.Cu" "In11.Cu" "In12.Cu" "In13.Cu" "In14.Cu"
			"In15.Cu" "In16.Cu"
		)
		(hatch none 0.5)
		(connect_pads
			(clearance 0)
		)
		(min_thickness 0.25)
		(keepout
			(tracks not_allowed)
			(vias allowed)
			(pads allowed)
			(copperpour not_allowed)
			(footprints allowed)
		)
		(placement
			(enabled no)
			(sheetname "")
		)
		(fill
			(thermal_gap 0.5)
			(thermal_bridge_width 0.5)
			(island_removal_mode 0)
		)
		(polygon
			(pts
				(arc
					(start 374.006364 -217.878406)
					(mid 373.348504 -217.878406)
					(end 374.006364 -217.878406)
				)
			)
		)
	)
	(zone
		(layers "F.Cu" "B.Cu" "In1.Cu" "In2.Cu" "In3.Cu" "In4.Cu" "In5.Cu" "In6.Cu"
			"In7.Cu" "In8.Cu" "In9.Cu" "In10.Cu" "In11.Cu" "In12.Cu" "In13.Cu" "In14.Cu"
			"In15.Cu" "In16.Cu"
		)
		(hatch none 0.5)
		(connect_pads
			(clearance 0)
		)
		(min_thickness 0.25)
		(keepout
			(tracks not_allowed)
			(vias allowed)
			(pads allowed)
			(copperpour not_allowed)
			(footprints allowed)
		)
		(placement
			(enabled no)
			(sheetname "")
		)
		(fill
			(thermal_gap 0.5)
			(thermal_bridge_width 0.5)
			(island_removal_mode 0)
		)
		(polygon
			(pts
				(arc
					(start 354.112068 -217.780108)
					(mid 354.040079 -217.707949)
					(end 353.941634 -217.681556)
				)
				(arc
					(start 353.941634 -217.681556)
					(mid 353.80244 -217.739212)
					(end 353.744784 -217.878406)
				)
				(arc
					(start 353.744784 -217.878406)
					(mid 353.751541 -217.929287)
					(end 353.7712 -217.976704)
				)
				(arc
					(start 354.240846 -218.79052)
					(mid 354.312835 -218.862679)
					(end 354.41128 -218.889072)
				)
				(arc
					(start 354.41128 -218.889072)
					(mid 354.550474 -218.831416)
					(end 354.60813 -218.692222)
				)
				(arc
					(start 354.60813 -218.692222)
					(mid 354.601373 -218.641341)
					(end 354.581714 -218.593924)
				)
			)
		)
	)
	(zone
		(layers "F.Cu" "B.Cu" "In1.Cu" "In2.Cu" "In3.Cu" "In4.Cu" "In5.Cu" "In6.Cu"
			"In7.Cu" "In8.Cu" "In9.Cu" "In10.Cu" "In11.Cu" "In12.Cu" "In13.Cu" "In14.Cu"
			"In15.Cu" "In16.Cu"
		)
		(hatch none 0.5)
		(connect_pads
			(clearance 0)
		)
		(min_thickness 0.25)
		(keepout
			(tracks not_allowed)
			(vias allowed)
			(pads allowed)
			(copperpour not_allowed)
			(footprints allowed)
		)
		(placement
			(enabled no)
			(sheetname "")
		)
		(fill
			(thermal_gap 0.5)
			(thermal_bridge_width 0.5)
			(island_removal_mode 0)
		)
		(polygon
			(pts
				(arc
					(start 341.58301 -218.692222)
					(mid 340.92515 -218.692222)
					(end 341.58301 -218.692222)
				)
			)
		)
	)
	(zone
		(layers "F.Cu" "B.Cu" "In1.Cu" "In2.Cu" "In3.Cu" "In4.Cu" "In5.Cu" "In6.Cu"
			"In7.Cu" "In8.Cu" "In9.Cu" "In10.Cu" "In11.Cu" "In12.Cu" "In13.Cu" "In14.Cu"
			"In15.Cu" "In16.Cu"
		)
		(hatch none 0.5)
		(connect_pads
			(clearance 0)
		)
		(min_thickness 0.25)
		(keepout
			(tracks not_allowed)
			(vias allowed)
			(pads allowed)
			(copperpour not_allowed)
			(footprints allowed)
		)
		(placement
			(enabled no)
			(sheetname "")
		)
		(fill
			(thermal_gap 0.5)
			(thermal_bridge_width 0.5)
			(island_removal_mode 0)
		)
		(polygon
			(pts
				(arc
					(start 69.422518 -403.502876)
					(mid 69.041518 -403.883876)
					(end 69.422518 -404.264876)
				)
				(arc
					(start 70.286118 -404.264876)
					(mid 70.667118 -403.883876)
					(end 70.286118 -403.502876)
				)
			)
		)
	)
	(zone
		(layers "F.Cu" "B.Cu" "In1.Cu" "In2.Cu" "In3.Cu" "In4.Cu" "In5.Cu" "In6.Cu"
			"In7.Cu" "In8.Cu" "In9.Cu" "In10.Cu" "In11.Cu" "In12.Cu" "In13.Cu" "In14.Cu"
			"In15.Cu" "In16.Cu"
		)
		(hatch none 0.5)
		(connect_pads
			(clearance 0)
		)
		(min_thickness 0.25)
		(keepout
			(tracks not_allowed)
			(vias allowed)
			(pads allowed)
			(copperpour not_allowed)
			(footprints allowed)
		)
		(placement
			(enabled no)
			(sheetname "")
		)
		(fill
			(thermal_gap 0.5)
			(thermal_bridge_width 0.5)
			(island_removal_mode 0)
		)
		(polygon
			(pts
				(arc
					(start 366.487964 -217.878406)
					(mid 365.830104 -217.878406)
					(end 366.487964 -217.878406)
				)
			)
		)
	)
	(zone
		(layers "F.Cu" "B.Cu" "In1.Cu" "In2.Cu" "In3.Cu" "In4.Cu" "In5.Cu" "In6.Cu"
			"In7.Cu" "In8.Cu" "In9.Cu" "In10.Cu" "In11.Cu" "In12.Cu" "In13.Cu" "In14.Cu"
			"In15.Cu" "In16.Cu"
		)
		(hatch none 0.5)
		(connect_pads
			(clearance 0)
		)
		(min_thickness 0.25)
		(keepout
			(tracks not_allowed)
			(vias allowed)
			(pads allowed)
			(copperpour not_allowed)
			(footprints allowed)
		)
		(placement
			(enabled no)
			(sheetname "")
		)
		(fill
			(thermal_gap 0.5)
			(thermal_bridge_width 0.5)
			(island_removal_mode 0)
		)
		(polygon
			(pts
				(arc
					(start 350.352868 -217.780108)
					(mid 350.280879 -217.707949)
					(end 350.182434 -217.681556)
				)
				(arc
					(start 350.182434 -217.681556)
					(mid 350.04324 -217.739212)
					(end 349.985584 -217.878406)
				)
				(arc
					(start 349.985584 -217.878406)
					(mid 349.992341 -217.929287)
					(end 350.012 -217.976704)
				)
				(arc
					(start 350.481646 -218.79052)
					(mid 350.553635 -218.862679)
					(end 350.65208 -218.889072)
				)
				(arc
					(start 350.65208 -218.889072)
					(mid 350.791274 -218.831416)
					(end 350.84893 -218.692222)
				)
				(arc
					(start 350.84893 -218.692222)
					(mid 350.842173 -218.641341)
					(end 350.822514 -218.593924)
				)
			)
		)
	)
	(zone
		(layers "F.Cu" "B.Cu" "In1.Cu" "In2.Cu" "In3.Cu" "In4.Cu" "In5.Cu" "In6.Cu"
			"In7.Cu" "In8.Cu" "In9.Cu" "In10.Cu" "In11.Cu" "In12.Cu" "In13.Cu" "In14.Cu"
			"In15.Cu" "In16.Cu"
		)
		(hatch none 0.5)
		(connect_pads
			(clearance 0)
		)
		(min_thickness 0.25)
		(keepout
			(tracks not_allowed)
			(vias allowed)
			(pads allowed)
			(copperpour not_allowed)
			(footprints allowed)
		)
		(placement
			(enabled no)
			(sheetname "")
		)
		(fill
			(thermal_gap 0.5)
			(thermal_bridge_width 0.5)
			(island_removal_mode 0)
		)
		(polygon
			(pts
				(arc
					(start 131.234942 -225.203258)
					(mid 130.577082 -225.203258)
					(end 131.234942 -225.203258)
				)
			)
		)
	)
	(zone
		(layers "F.Cu" "B.Cu" "In1.Cu" "In2.Cu" "In3.Cu" "In4.Cu" "In5.Cu" "In6.Cu"
			"In7.Cu" "In8.Cu" "In9.Cu" "In10.Cu" "In11.Cu" "In12.Cu" "In13.Cu" "In14.Cu"
			"In15.Cu" "In16.Cu"
		)
		(hatch none 0.5)
		(connect_pads
			(clearance 0)
		)
		(min_thickness 0.25)
		(keepout
			(tracks not_allowed)
			(vias allowed)
			(pads allowed)
			(copperpour not_allowed)
			(footprints allowed)
		)
		(placement
			(enabled no)
			(sheetname "")
		)
		(fill
			(thermal_gap 0.5)
			(thermal_bridge_width 0.5)
			(island_removal_mode 0)
		)
		(polygon
			(pts
				(arc
					(start 349.571056 -214.622634)
					(mid 348.913196 -214.622634)
					(end 349.571056 -214.622634)
				)
			)
		)
	)
	(zone
		(layers "F.Cu" "B.Cu" "In1.Cu" "In2.Cu" "In3.Cu" "In4.Cu" "In5.Cu" "In6.Cu"
			"In7.Cu" "In8.Cu" "In9.Cu" "In10.Cu" "In11.Cu" "In12.Cu" "In13.Cu" "In14.Cu"
			"In15.Cu" "In16.Cu"
		)
		(hatch none 0.5)
		(connect_pads
			(clearance 0)
		)
		(min_thickness 0.25)
		(keepout
			(tracks not_allowed)
			(vias allowed)
			(pads allowed)
			(copperpour not_allowed)
			(footprints allowed)
		)
		(placement
			(enabled no)
			(sheetname "")
		)
		(fill
			(thermal_gap 0.5)
			(thermal_bridge_width 0.5)
			(island_removal_mode 0)
		)
		(polygon
			(pts
				(arc
					(start 379.17501 -221.94774)
					(mid 378.51715 -221.94774)
					(end 379.17501 -221.94774)
				)
			)
		)
	)
	(zone
		(layers "F.Cu" "B.Cu" "In1.Cu" "In2.Cu" "In3.Cu" "In4.Cu" "In5.Cu" "In6.Cu"
			"In7.Cu" "In8.Cu" "In9.Cu" "In10.Cu" "In11.Cu" "In12.Cu" "In13.Cu" "In14.Cu"
			"In15.Cu" "In16.Cu"
		)
		(hatch none 0.5)
		(connect_pads
			(clearance 0)
		)
		(min_thickness 0.25)
		(keepout
			(tracks not_allowed)
			(vias allowed)
			(pads allowed)
			(copperpour not_allowed)
			(footprints allowed)
		)
		(placement
			(enabled no)
			(sheetname "")
		)
		(fill
			(thermal_gap 0.5)
			(thermal_bridge_width 0.5)
			(island_removal_mode 0)
		)
		(polygon
			(pts
				(arc
					(start 345.123262 -282.208986)
					(mid 344.926412 -282.405836)
					(end 345.123262 -282.602686)
				)
				(arc
					(start 346.063062 -282.602686)
					(mid 346.259912 -282.405836)
					(end 346.063062 -282.208986)
				)
			)
		)
	)
	(zone
		(layers "F.Cu" "B.Cu" "In1.Cu" "In2.Cu" "In3.Cu" "In4.Cu" "In5.Cu" "In6.Cu"
			"In7.Cu" "In8.Cu" "In9.Cu" "In10.Cu" "In11.Cu" "In12.Cu" "In13.Cu" "In14.Cu"
			"In15.Cu" "In16.Cu"
		)
		(hatch none 0.5)
		(connect_pads
			(clearance 0)
		)
		(min_thickness 0.25)
		(keepout
			(tracks not_allowed)
			(vias allowed)
			(pads allowed)
			(copperpour not_allowed)
			(footprints allowed)
		)
		(placement
			(enabled no)
			(sheetname "")
		)
		(fill
			(thermal_gap 0.5)
			(thermal_bridge_width 0.5)
			(island_removal_mode 0)
		)
		(polygon
			(pts
				(arc
					(start 104.920542 -225.203258)
					(mid 104.262682 -225.203258)
					(end 104.920542 -225.203258)
				)
			)
		)
	)
	(zone
		(layers "F.Cu" "B.Cu" "In1.Cu" "In2.Cu" "In3.Cu" "In4.Cu" "In5.Cu" "In6.Cu"
			"In7.Cu" "In8.Cu" "In9.Cu" "In10.Cu" "In11.Cu" "In12.Cu" "In13.Cu" "In14.Cu"
			"In15.Cu" "In16.Cu"
		)
		(hatch none 0.5)
		(connect_pads
			(clearance 0)
		)
		(min_thickness 0.25)
		(keepout
			(tracks not_allowed)
			(vias allowed)
			(pads allowed)
			(copperpour not_allowed)
			(footprints allowed)
		)
		(placement
			(enabled no)
			(sheetname "")
		)
		(fill
			(thermal_gap 0.5)
			(thermal_bridge_width 0.5)
			(island_removal_mode 0)
		)
		(polygon
			(pts
				(arc
					(start 352.970592 -282.405836)
					(mid 352.312732 -282.405836)
					(end 352.970592 -282.405836)
				)
			)
		)
	)
	(zone
		(layers "F.Cu" "B.Cu" "In1.Cu" "In2.Cu" "In3.Cu" "In4.Cu" "In5.Cu" "In6.Cu"
			"In7.Cu" "In8.Cu" "In9.Cu" "In10.Cu" "In11.Cu" "In12.Cu" "In13.Cu" "In14.Cu"
			"In15.Cu" "In16.Cu"
		)
		(hatch none 0.5)
		(connect_pads
			(clearance 0)
		)
		(min_thickness 0.25)
		(keepout
			(tracks not_allowed)
			(vias allowed)
			(pads allowed)
			(copperpour not_allowed)
			(footprints allowed)
		)
		(placement
			(enabled no)
			(sheetname "")
		)
		(fill
			(thermal_gap 0.5)
			(thermal_bridge_width 0.5)
			(island_removal_mode 0)
		)
		(polygon
			(pts
				(arc
					(start 357.323644 -49.826672)
					(mid 356.942644 -50.207672)
					(end 357.323644 -50.588672)
				)
				(arc
					(start 358.187244 -50.588672)
					(mid 358.568244 -50.207672)
					(end 358.187244 -49.826672)
				)
			)
		)
	)
	(zone
		(layers "F.Cu" "B.Cu" "In1.Cu" "In2.Cu" "In3.Cu" "In4.Cu" "In5.Cu" "In6.Cu"
			"In7.Cu" "In8.Cu" "In9.Cu" "In10.Cu" "In11.Cu" "In12.Cu" "In13.Cu" "In14.Cu"
			"In15.Cu" "In16.Cu"
		)
		(hatch none 0.5)
		(connect_pads
			(clearance 0)
		)
		(min_thickness 0.25)
		(keepout
			(tracks not_allowed)
			(vias allowed)
			(pads allowed)
			(copperpour not_allowed)
			(footprints allowed)
		)
		(placement
			(enabled no)
			(sheetname "")
		)
		(fill
			(thermal_gap 0.5)
			(thermal_bridge_width 0.5)
			(island_removal_mode 0)
		)
		(polygon
			(pts
				(arc
					(start 103.81488 -213.646766)
					(mid 103.747172 -213.574915)
					(end 103.652066 -213.548468)
				)
				(arc
					(start 103.652066 -213.548468)
					(mid 103.521852 -213.602404)
					(end 103.467916 -213.732618)
				)
				(arc
					(start 103.467916 -213.732618)
					(mid 103.473367 -213.776839)
					(end 103.489252 -213.81847)
				)
				(arc
					(start 103.958644 -214.708486)
					(mid 104.026352 -214.780337)
					(end 104.121458 -214.806784)
				)
				(arc
					(start 104.121458 -214.806784)
					(mid 104.251672 -214.752848)
					(end 104.305608 -214.622634)
				)
				(arc
					(start 104.305608 -214.622634)
					(mid 104.300157 -214.578413)
					(end 104.284272 -214.536782)
				)
			)
		)
	)
	(zone
		(layers "F.Cu" "B.Cu" "In1.Cu" "In2.Cu" "In3.Cu" "In4.Cu" "In5.Cu" "In6.Cu"
			"In7.Cu" "In8.Cu" "In9.Cu" "In10.Cu" "In11.Cu" "In12.Cu" "In13.Cu" "In14.Cu"
			"In15.Cu" "In16.Cu"
		)
		(hatch none 0.5)
		(connect_pads
			(clearance 0)
		)
		(min_thickness 0.25)
		(keepout
			(tracks not_allowed)
			(vias allowed)
			(pads allowed)
			(copperpour not_allowed)
			(footprints allowed)
		)
		(placement
			(enabled no)
			(sheetname "")
		)
		(fill
			(thermal_gap 0.5)
			(thermal_bridge_width 0.5)
			(island_removal_mode 0)
		)
		(polygon
			(pts
				(arc
					(start 124.600462 -289.003232)
					(mid 124.616386 -288.961481)
					(end 124.621798 -288.917126)
				)
				(arc
					(start 124.621798 -288.917126)
					(mid 124.567862 -288.786912)
					(end 124.437648 -288.732976)
				)
				(arc
					(start 124.437648 -288.732976)
					(mid 124.342628 -288.759384)
					(end 124.274834 -288.83102)
				)
				(arc
					(start 123.80468 -289.721036)
					(mid 123.788756 -289.762787)
					(end 123.783344 -289.807142)
				)
				(arc
					(start 123.783344 -289.807142)
					(mid 123.83728 -289.937356)
					(end 123.967494 -289.991292)
				)
				(arc
					(start 123.967494 -289.991292)
					(mid 124.062514 -289.964884)
					(end 124.130308 -289.893248)
				)
			)
		)
	)
	(zone
		(layers "F.Cu" "B.Cu" "In1.Cu" "In2.Cu" "In3.Cu" "In4.Cu" "In5.Cu" "In6.Cu"
			"In7.Cu" "In8.Cu" "In9.Cu" "In10.Cu" "In11.Cu" "In12.Cu" "In13.Cu" "In14.Cu"
			"In15.Cu" "In16.Cu"
		)
		(hatch none 0.5)
		(connect_pads
			(clearance 0)
		)
		(min_thickness 0.25)
		(keepout
			(tracks not_allowed)
			(vias allowed)
			(pads allowed)
			(copperpour not_allowed)
			(footprints allowed)
		)
		(placement
			(enabled no)
			(sheetname "")
		)
		(fill
			(thermal_gap 0.5)
			(thermal_bridge_width 0.5)
			(island_removal_mode 0)
		)
		(polygon
			(pts
				(arc
					(start 368.367564 -217.878406)
					(mid 367.709704 -217.878406)
					(end 368.367564 -217.878406)
				)
			)
		)
	)
	(zone
		(layers "F.Cu" "B.Cu" "In1.Cu" "In2.Cu" "In3.Cu" "In4.Cu" "In5.Cu" "In6.Cu"
			"In7.Cu" "In8.Cu" "In9.Cu" "In10.Cu" "In11.Cu" "In12.Cu" "In13.Cu" "In14.Cu"
			"In15.Cu" "In16.Cu"
		)
		(hatch none 0.5)
		(connect_pads
			(clearance 0)
		)
		(min_thickness 0.25)
		(keepout
			(tracks not_allowed)
			(vias allowed)
			(pads allowed)
			(copperpour not_allowed)
			(footprints allowed)
		)
		(placement
			(enabled no)
			(sheetname "")
		)
		(fill
			(thermal_gap 0.5)
			(thermal_bridge_width 0.5)
			(island_removal_mode 0)
		)
		(polygon
			(pts
				(arc
					(start 352.471228 -275.796502)
					(mid 352.451544 -275.843912)
					(end 352.444812 -275.8948)
				)
				(arc
					(start 352.444812 -275.8948)
					(mid 352.502468 -276.033994)
					(end 352.641662 -276.09165)
				)
				(arc
					(start 352.641662 -276.09165)
					(mid 352.740093 -276.065234)
					(end 352.812096 -275.993098)
				)
				(arc
					(start 353.281996 -275.179028)
					(mid 353.30168 -275.131618)
					(end 353.308412 -275.08073)
				)
				(arc
					(start 353.308412 -275.08073)
					(mid 353.250756 -274.941536)
					(end 353.111562 -274.88388)
				)
				(arc
					(start 353.111562 -274.88388)
					(mid 353.013131 -274.910296)
					(end 352.941128 -274.982432)
				)
			)
		)
	)
	(zone
		(layers "F.Cu" "B.Cu" "In1.Cu" "In2.Cu" "In3.Cu" "In4.Cu" "In5.Cu" "In6.Cu"
			"In7.Cu" "In8.Cu" "In9.Cu" "In10.Cu" "In11.Cu" "In12.Cu" "In13.Cu" "In14.Cu"
			"In15.Cu" "In16.Cu"
		)
		(hatch none 0.5)
		(connect_pads
			(clearance 0)
		)
		(min_thickness 0.25)
		(keepout
			(tracks not_allowed)
			(vias allowed)
			(pads allowed)
			(copperpour not_allowed)
			(footprints allowed)
		)
		(placement
			(enabled no)
			(sheetname "")
		)
		(fill
			(thermal_gap 0.5)
			(thermal_bridge_width 0.5)
			(island_removal_mode 0)
		)
		(polygon
			(pts
				(arc
					(start 106.252264 -277.522432)
					(mid 106.910124 -277.522432)
					(end 106.252264 -277.522432)
				)
			)
		)
	)
	(zone
		(layers "F.Cu" "B.Cu" "In1.Cu" "In2.Cu" "In3.Cu" "In4.Cu" "In5.Cu" "In6.Cu"
			"In7.Cu" "In8.Cu" "In9.Cu" "In10.Cu" "In11.Cu" "In12.Cu" "In13.Cu" "In14.Cu"
			"In15.Cu" "In16.Cu"
		)
		(hatch none 0.5)
		(connect_pads
			(clearance 0)
		)
		(min_thickness 0.25)
		(keepout
			(tracks not_allowed)
			(vias allowed)
			(pads allowed)
			(copperpour not_allowed)
			(footprints allowed)
		)
		(placement
			(enabled no)
			(sheetname "")
		)
		(fill
			(thermal_gap 0.5)
			(thermal_bridge_width 0.5)
			(island_removal_mode 0)
		)
		(polygon
			(pts
				(arc
					(start 356.559612 -43.226736)
					(mid 356.178612 -43.607736)
					(end 356.559612 -43.988736)
				)
				(arc
					(start 357.423212 -43.988736)
					(mid 357.804212 -43.607736)
					(end 357.423212 -43.226736)
				)
			)
		)
	)
	(zone
		(layers "F.Cu" "B.Cu" "In1.Cu" "In2.Cu" "In3.Cu" "In4.Cu" "In5.Cu" "In6.Cu"
			"In7.Cu" "In8.Cu" "In9.Cu" "In10.Cu" "In11.Cu" "In12.Cu" "In13.Cu" "In14.Cu"
			"In15.Cu" "In16.Cu"
		)
		(hatch none 0.5)
		(connect_pads
			(clearance 0)
		)
		(min_thickness 0.25)
		(keepout
			(tracks not_allowed)
			(vias allowed)
			(pads allowed)
			(copperpour not_allowed)
			(footprints allowed)
		)
		(placement
			(enabled no)
			(sheetname "")
		)
		(fill
			(thermal_gap 0.5)
			(thermal_bridge_width 0.5)
			(island_removal_mode 0)
		)
		(polygon
			(pts
				(arc
					(start 94.193614 -288.818828)
					(mid 94.17393 -288.866238)
					(end 94.167198 -288.917126)
				)
				(arc
					(start 94.167198 -288.917126)
					(mid 94.224854 -289.05632)
					(end 94.364048 -289.113976)
				)
				(arc
					(start 94.364048 -289.113976)
					(mid 94.462479 -289.08756)
					(end 94.534482 -289.015424)
				)
				(arc
					(start 95.004382 -288.201354)
					(mid 95.024066 -288.153944)
					(end 95.030798 -288.103056)
				)
				(arc
					(start 95.030798 -288.103056)
					(mid 94.973142 -287.963862)
					(end 94.833948 -287.906206)
				)
				(arc
					(start 94.833948 -287.906206)
					(mid 94.735517 -287.932622)
					(end 94.663514 -288.004758)
				)
			)
		)
	)
	(zone
		(layers "F.Cu" "B.Cu" "In1.Cu" "In2.Cu" "In3.Cu" "In4.Cu" "In5.Cu" "In6.Cu"
			"In7.Cu" "In8.Cu" "In9.Cu" "In10.Cu" "In11.Cu" "In12.Cu" "In13.Cu" "In14.Cu"
			"In15.Cu" "In16.Cu"
		)
		(hatch none 0.5)
		(connect_pads
			(clearance 0)
		)
		(min_thickness 0.25)
		(keepout
			(tracks not_allowed)
			(vias allowed)
			(pads allowed)
			(copperpour not_allowed)
			(footprints allowed)
		)
		(placement
			(enabled no)
			(sheetname "")
		)
		(fill
			(thermal_gap 0.5)
			(thermal_bridge_width 0.5)
			(island_removal_mode 0)
		)
		(polygon
			(pts
				(arc
					(start 123.198382 -284.74924)
					(mid 123.126393 -284.677081)
					(end 123.027948 -284.650688)
				)
				(arc
					(start 123.027948 -284.650688)
					(mid 122.888754 -284.708344)
					(end 122.831098 -284.847538)
				)
				(arc
					(start 122.831098 -284.847538)
					(mid 122.837855 -284.898419)
					(end 122.857514 -284.945836)
				)
				(arc
					(start 123.32716 -285.759652)
					(mid 123.399149 -285.831811)
					(end 123.497594 -285.858204)
				)
				(arc
					(start 123.497594 -285.858204)
					(mid 123.636788 -285.800548)
					(end 123.694444 -285.661354)
				)
				(arc
					(start 123.694444 -285.661354)
					(mid 123.687687 -285.610473)
					(end 123.668028 -285.563056)
				)
			)
		)
	)
	(zone
		(layers "F.Cu" "B.Cu" "In1.Cu" "In2.Cu" "In3.Cu" "In4.Cu" "In5.Cu" "In6.Cu"
			"In7.Cu" "In8.Cu" "In9.Cu" "In10.Cu" "In11.Cu" "In12.Cu" "In13.Cu" "In14.Cu"
			"In15.Cu" "In16.Cu"
		)
		(hatch none 0.5)
		(connect_pads
			(clearance 0)
		)
		(min_thickness 0.25)
		(keepout
			(tracks not_allowed)
			(vias allowed)
			(pads allowed)
			(copperpour not_allowed)
			(footprints allowed)
		)
		(placement
			(enabled no)
			(sheetname "")
		)
		(fill
			(thermal_gap 0.5)
			(thermal_bridge_width 0.5)
			(island_removal_mode 0)
		)
		(polygon
			(pts
				(arc
					(start 101.553264 -282.405836)
					(mid 102.211124 -282.405836)
					(end 101.553264 -282.405836)
				)
			)
		)
	)
	(zone
		(layers "F.Cu" "B.Cu" "In1.Cu" "In2.Cu" "In3.Cu" "In4.Cu" "In5.Cu" "In6.Cu"
			"In7.Cu" "In8.Cu" "In9.Cu" "In10.Cu" "In11.Cu" "In12.Cu" "In13.Cu" "In14.Cu"
			"In15.Cu" "In16.Cu"
		)
		(hatch none 0.5)
		(connect_pads
			(clearance 0)
		)
		(min_thickness 0.25)
		(keepout
			(tracks not_allowed)
			(vias allowed)
			(pads allowed)
			(copperpour not_allowed)
			(footprints allowed)
		)
		(placement
			(enabled no)
			(sheetname "")
		)
		(fill
			(thermal_gap 0.5)
			(thermal_bridge_width 0.5)
			(island_removal_mode 0)
		)
		(polygon
			(pts
				(arc
					(start 319.296288 -403.502876)
					(mid 318.915288 -403.883876)
					(end 319.296288 -404.264876)
				)
				(arc
					(start 320.159888 -404.264876)
					(mid 320.540888 -403.883876)
					(end 320.159888 -403.502876)
				)
			)
		)
	)
	(zone
		(layers "F.Cu" "B.Cu" "In1.Cu" "In2.Cu" "In3.Cu" "In4.Cu" "In5.Cu" "In6.Cu"
			"In7.Cu" "In8.Cu" "In9.Cu" "In10.Cu" "In11.Cu" "In12.Cu" "In13.Cu" "In14.Cu"
			"In15.Cu" "In16.Cu"
		)
		(hatch none 0.5)
		(connect_pads
			(clearance 0)
		)
		(min_thickness 0.25)
		(keepout
			(tracks not_allowed)
			(vias allowed)
			(pads allowed)
			(copperpour not_allowed)
			(footprints allowed)
		)
		(placement
			(enabled no)
			(sheetname "")
		)
		(fill
			(thermal_gap 0.5)
			(thermal_bridge_width 0.5)
			(island_removal_mode 0)
		)
		(polygon
			(pts
				(arc
					(start 105.860342 -217.064336)
					(mid 105.202482 -217.064336)
					(end 105.860342 -217.064336)
				)
			)
		)
	)
	(zone
		(layers "F.Cu" "B.Cu" "In1.Cu" "In2.Cu" "In3.Cu" "In4.Cu" "In5.Cu" "In6.Cu"
			"In7.Cu" "In8.Cu" "In9.Cu" "In10.Cu" "In11.Cu" "In12.Cu" "In13.Cu" "In14.Cu"
			"In15.Cu" "In16.Cu"
		)
		(hatch none 0.5)
		(connect_pads
			(clearance 0)
		)
		(min_thickness 0.25)
		(keepout
			(tracks not_allowed)
			(vias allowed)
			(pads allowed)
			(copperpour not_allowed)
			(footprints allowed)
		)
		(placement
			(enabled no)
			(sheetname "")
		)
		(fill
			(thermal_gap 0.5)
			(thermal_bridge_width 0.5)
			(island_removal_mode 0)
		)
		(polygon
			(pts
				(arc
					(start 19.397726 -382.512824)
					(mid 19.016726 -382.893824)
					(end 19.397726 -383.274824)
				)
				(arc
					(start 20.261326 -383.274824)
					(mid 20.642326 -382.893824)
					(end 20.261326 -382.512824)
				)
			)
		)
	)
	(zone
		(layers "F.Cu" "B.Cu" "In1.Cu" "In2.Cu" "In3.Cu" "In4.Cu" "In5.Cu" "In6.Cu"
			"In7.Cu" "In8.Cu" "In9.Cu" "In10.Cu" "In11.Cu" "In12.Cu" "In13.Cu" "In14.Cu"
			"In15.Cu" "In16.Cu"
		)
		(hatch none 0.5)
		(connect_pads
			(clearance 0)
		)
		(min_thickness 0.25)
		(keepout
			(tracks not_allowed)
			(vias allowed)
			(pads allowed)
			(copperpour not_allowed)
			(footprints allowed)
		)
		(placement
			(enabled no)
			(sheetname "")
		)
		(fill
			(thermal_gap 0.5)
			(thermal_bridge_width 0.5)
			(island_removal_mode 0)
		)
		(polygon
			(pts
				(arc
					(start 350.98101 -221.94774)
					(mid 350.32315 -221.94774)
					(end 350.98101 -221.94774)
				)
			)
		)
	)
	(zone
		(layers "F.Cu" "B.Cu" "In1.Cu" "In2.Cu" "In3.Cu" "In4.Cu" "In5.Cu" "In6.Cu"
			"In7.Cu" "In8.Cu" "In9.Cu" "In10.Cu" "In11.Cu" "In12.Cu" "In13.Cu" "In14.Cu"
			"In15.Cu" "In16.Cu"
		)
		(hatch none 0.5)
		(connect_pads
			(clearance 0)
		)
		(min_thickness 0.25)
		(keepout
			(tracks not_allowed)
			(vias allowed)
			(pads allowed)
			(copperpour not_allowed)
			(footprints allowed)
		)
		(placement
			(enabled no)
			(sheetname "")
		)
		(fill
			(thermal_gap 0.5)
			(thermal_bridge_width 0.5)
			(island_removal_mode 0)
		)
		(polygon
			(pts
				(xy 470.499948 -377.40844) (xy 470.499948 -372.40845) (xy 470.804748 -372.71325) (xy 470.804748 -377.10364)
			)
		)
	)
	(zone
		(layers "F.Cu" "B.Cu" "In1.Cu" "In2.Cu" "In3.Cu" "In4.Cu" "In5.Cu" "In6.Cu"
			"In7.Cu" "In8.Cu" "In9.Cu" "In10.Cu" "In11.Cu" "In12.Cu" "In13.Cu" "In14.Cu"
			"In15.Cu" "In16.Cu"
		)
		(hatch none 0.5)
		(connect_pads
			(clearance 0)
		)
		(min_thickness 0.25)
		(keepout
			(tracks not_allowed)
			(vias allowed)
			(pads allowed)
			(copperpour not_allowed)
			(footprints allowed)
		)
		(placement
			(enabled no)
			(sheetname "")
		)
		(fill
			(thermal_gap 0.5)
			(thermal_bridge_width 0.5)
			(island_removal_mode 0)
		)
		(polygon
			(pts
				(arc
					(start 357.766366 -38.793928)
					(mid 357.385366 -38.412928)
					(end 357.004366 -38.793928)
				)
				(arc
					(start 357.004366 -39.657528)
					(mid 357.385366 -40.038528)
					(end 357.766366 -39.657528)
				)
			)
		)
	)
	(zone
		(layers "F.Cu" "B.Cu" "In1.Cu" "In2.Cu" "In3.Cu" "In4.Cu" "In5.Cu" "In6.Cu"
			"In7.Cu" "In8.Cu" "In9.Cu" "In10.Cu" "In11.Cu" "In12.Cu" "In13.Cu" "In14.Cu"
			"In15.Cu" "In16.Cu"
		)
		(hatch none 0.5)
		(connect_pads
			(clearance 0)
		)
		(min_thickness 0.25)
		(keepout
			(tracks not_allowed)
			(vias allowed)
			(pads allowed)
			(copperpour not_allowed)
			(footprints allowed)
		)
		(placement
			(enabled no)
			(sheetname "")
		)
		(fill
			(thermal_gap 0.5)
			(thermal_bridge_width 0.5)
			(island_removal_mode 0)
		)
		(polygon
			(pts
				(arc
					(start 376.35561 -223.575626)
					(mid 375.69775 -223.575626)
					(end 376.35561 -223.575626)
				)
			)
		)
	)
	(zone
		(layers "F.Cu" "B.Cu" "In1.Cu" "In2.Cu" "In3.Cu" "In4.Cu" "In5.Cu" "In6.Cu"
			"In7.Cu" "In8.Cu" "In9.Cu" "In10.Cu" "In11.Cu" "In12.Cu" "In13.Cu" "In14.Cu"
			"In15.Cu" "In16.Cu"
		)
		(hatch none 0.5)
		(connect_pads
			(clearance 0)
		)
		(min_thickness 0.25)
		(keepout
			(tracks not_allowed)
			(vias allowed)
			(pads allowed)
			(copperpour not_allowed)
			(footprints allowed)
		)
		(placement
			(enabled no)
			(sheetname "")
		)
		(fill
			(thermal_gap 0.5)
			(thermal_bridge_width 0.5)
			(island_removal_mode 0)
		)
		(polygon
			(pts
				(arc
					(start 358.029764 -224.389442)
					(mid 357.371904 -224.389442)
					(end 358.029764 -224.389442)
				)
			)
		)
	)
	(zone
		(layers "F.Cu" "B.Cu" "In1.Cu" "In2.Cu" "In3.Cu" "In4.Cu" "In5.Cu" "In6.Cu"
			"In7.Cu" "In8.Cu" "In9.Cu" "In10.Cu" "In11.Cu" "In12.Cu" "In13.Cu" "In14.Cu"
			"In15.Cu" "In16.Cu"
		)
		(hatch none 0.5)
		(connect_pads
			(clearance 0)
		)
		(min_thickness 0.25)
		(keepout
			(tracks not_allowed)
			(vias allowed)
			(pads allowed)
			(copperpour not_allowed)
			(footprints allowed)
		)
		(placement
			(enabled no)
			(sheetname "")
		)
		(fill
			(thermal_gap 0.5)
			(thermal_bridge_width 0.5)
			(island_removal_mode 0)
		)
		(polygon
			(pts
				(arc
					(start 366.01781 -218.692222)
					(mid 365.35995 -218.692222)
					(end 366.01781 -218.692222)
				)
			)
		)
	)
	(zone
		(layers "F.Cu" "B.Cu" "In1.Cu" "In2.Cu" "In3.Cu" "In4.Cu" "In5.Cu" "In6.Cu"
			"In7.Cu" "In8.Cu" "In9.Cu" "In10.Cu" "In11.Cu" "In12.Cu" "In13.Cu" "In14.Cu"
			"In15.Cu" "In16.Cu"
		)
		(hatch none 0.5)
		(connect_pads
			(clearance 0)
		)
		(min_thickness 0.25)
		(keepout
			(tracks not_allowed)
			(vias allowed)
			(pads allowed)
			(copperpour not_allowed)
			(footprints allowed)
		)
		(placement
			(enabled no)
			(sheetname "")
		)
		(fill
			(thermal_gap 0.5)
			(thermal_bridge_width 0.5)
			(island_removal_mode 0)
		)
		(polygon
			(pts
				(arc
					(start 129.935478 -286.475424)
					(mid 129.277618 -286.475424)
					(end 129.935478 -286.475424)
				)
			)
		)
	)
	(zone
		(layers "F.Cu" "B.Cu" "In1.Cu" "In2.Cu" "In3.Cu" "In4.Cu" "In5.Cu" "In6.Cu"
			"In7.Cu" "In8.Cu" "In9.Cu" "In10.Cu" "In11.Cu" "In12.Cu" "In13.Cu" "In14.Cu"
			"In15.Cu" "In16.Cu"
		)
		(hatch none 0.5)
		(connect_pads
			(clearance 0)
		)
		(min_thickness 0.25)
		(keepout
			(tracks not_allowed)
			(vias allowed)
			(pads allowed)
			(copperpour not_allowed)
			(footprints allowed)
		)
		(placement
			(enabled no)
			(sheetname "")
		)
		(fill
			(thermal_gap 0.5)
			(thermal_bridge_width 0.5)
			(island_removal_mode 0)
		)
		(polygon
			(pts
				(arc
					(start 356.61981 -215.436704)
					(mid 355.96195 -215.436704)
					(end 356.61981 -215.436704)
				)
			)
		)
	)
	(zone
		(layers "F.Cu" "B.Cu" "In1.Cu" "In2.Cu" "In3.Cu" "In4.Cu" "In5.Cu" "In6.Cu"
			"In7.Cu" "In8.Cu" "In9.Cu" "In10.Cu" "In11.Cu" "In12.Cu" "In13.Cu" "In14.Cu"
			"In15.Cu" "In16.Cu"
		)
		(hatch none 0.5)
		(connect_pads
			(clearance 0)
		)
		(min_thickness 0.25)
		(keepout
			(tracks not_allowed)
			(vias allowed)
			(pads allowed)
			(copperpour not_allowed)
			(footprints allowed)
		)
		(placement
			(enabled no)
			(sheetname "")
		)
		(fill
			(thermal_gap 0.5)
			(thermal_bridge_width 0.5)
			(island_removal_mode 0)
		)
		(polygon
			(pts
				(arc
					(start 337.305396 -288.201354)
					(mid 337.32508 -288.153944)
					(end 337.331812 -288.103056)
				)
				(arc
					(start 337.331812 -288.103056)
					(mid 337.274156 -287.963862)
					(end 337.134962 -287.906206)
				)
				(arc
					(start 337.134962 -287.906206)
					(mid 337.036531 -287.932622)
					(end 336.964528 -288.004758)
				)
				(arc
					(start 336.494882 -288.818828)
					(mid 336.475198 -288.866238)
					(end 336.468466 -288.917126)
				)
				(arc
					(start 336.468466 -288.917126)
					(mid 336.526122 -289.05632)
					(end 336.665316 -289.113976)
				)
				(arc
					(start 336.665316 -289.113976)
					(mid 336.763747 -289.08756)
					(end 336.83575 -289.015424)
				)
			)
		)
	)
	(zone
		(layers "F.Cu" "B.Cu" "In1.Cu" "In2.Cu" "In3.Cu" "In4.Cu" "In5.Cu" "In6.Cu"
			"In7.Cu" "In8.Cu" "In9.Cu" "In10.Cu" "In11.Cu" "In12.Cu" "In13.Cu" "In14.Cu"
			"In15.Cu" "In16.Cu"
		)
		(hatch none 0.5)
		(connect_pads
			(clearance 0)
		)
		(min_thickness 0.25)
		(keepout
			(tracks not_allowed)
			(vias allowed)
			(pads allowed)
			(copperpour not_allowed)
			(footprints allowed)
		)
		(placement
			(enabled no)
			(sheetname "")
		)
		(fill
			(thermal_gap 0.5)
			(thermal_bridge_width 0.5)
			(island_removal_mode 0)
		)
		(polygon
			(pts
				(arc
					(start 98.733864 -285.661354)
					(mid 99.391724 -285.661354)
					(end 98.733864 -285.661354)
				)
			)
		)
	)
	(zone
		(layers "F.Cu" "B.Cu" "In1.Cu" "In2.Cu" "In3.Cu" "In4.Cu" "In5.Cu" "In6.Cu"
			"In7.Cu" "In8.Cu" "In9.Cu" "In10.Cu" "In11.Cu" "In12.Cu" "In13.Cu" "In14.Cu"
			"In15.Cu" "In16.Cu"
		)
		(hatch none 0.5)
		(connect_pads
			(clearance 0)
		)
		(min_thickness 0.25)
		(keepout
			(tracks not_allowed)
			(vias allowed)
			(pads allowed)
			(copperpour not_allowed)
			(footprints allowed)
		)
		(placement
			(enabled no)
			(sheetname "")
		)
		(fill
			(thermal_gap 0.5)
			(thermal_bridge_width 0.5)
			(island_removal_mode 0)
		)
		(polygon
			(pts
				(arc
					(start 113.848896 -217.878406)
					(mid 113.191036 -217.878406)
					(end 113.848896 -217.878406)
				)
			)
		)
	)
	(zone
		(layers "F.Cu" "B.Cu" "In1.Cu" "In2.Cu" "In3.Cu" "In4.Cu" "In5.Cu" "In6.Cu"
			"In7.Cu" "In8.Cu" "In9.Cu" "In10.Cu" "In11.Cu" "In12.Cu" "In13.Cu" "In14.Cu"
			"In15.Cu" "In16.Cu"
		)
		(hatch none 0.5)
		(connect_pads
			(clearance 0)
		)
		(min_thickness 0.25)
		(keepout
			(tracks not_allowed)
			(vias allowed)
			(pads allowed)
			(copperpour not_allowed)
			(footprints allowed)
		)
		(placement
			(enabled no)
			(sheetname "")
		)
		(fill
			(thermal_gap 0.5)
			(thermal_bridge_width 0.5)
			(island_removal_mode 0)
		)
		(polygon
			(pts
				(arc
					(start 94.222824 -281.59202)
					(mid 93.564964 -281.59202)
					(end 94.222824 -281.59202)
				)
			)
		)
	)
	(zone
		(layers "F.Cu" "B.Cu" "In1.Cu" "In2.Cu" "In3.Cu" "In4.Cu" "In5.Cu" "In6.Cu"
			"In7.Cu" "In8.Cu" "In9.Cu" "In10.Cu" "In11.Cu" "In12.Cu" "In13.Cu" "In14.Cu"
			"In15.Cu" "In16.Cu"
		)
		(hatch none 0.5)
		(connect_pads
			(clearance 0)
		)
		(min_thickness 0.25)
		(keepout
			(tracks not_allowed)
			(vias allowed)
			(pads allowed)
			(copperpour not_allowed)
			(footprints allowed)
		)
		(placement
			(enabled no)
			(sheetname "")
		)
		(fill
			(thermal_gap 0.5)
			(thermal_bridge_width 0.5)
			(island_removal_mode 0)
		)
		(polygon
			(pts
				(arc
					(start 128.415796 -213.732618)
					(mid 127.757936 -213.732618)
					(end 128.415796 -213.732618)
				)
			)
		)
	)
	(zone
		(layers "F.Cu" "B.Cu" "In1.Cu" "In2.Cu" "In3.Cu" "In4.Cu" "In5.Cu" "In6.Cu"
			"In7.Cu" "In8.Cu" "In9.Cu" "In10.Cu" "In11.Cu" "In12.Cu" "In13.Cu" "In14.Cu"
			"In15.Cu" "In16.Cu"
		)
		(hatch none 0.5)
		(connect_pads
			(clearance 0)
		)
		(min_thickness 0.25)
		(keepout
			(tracks not_allowed)
			(vias allowed)
			(pads allowed)
			(copperpour not_allowed)
			(footprints allowed)
		)
		(placement
			(enabled no)
			(sheetname "")
		)
		(fill
			(thermal_gap 0.5)
			(thermal_bridge_width 0.5)
			(island_removal_mode 0)
		)
		(polygon
			(pts
				(arc
					(start 114.788696 -221.133924)
					(mid 114.130836 -221.133924)
					(end 114.788696 -221.133924)
				)
			)
		)
	)
	(zone
		(layers "F.Cu" "B.Cu" "In1.Cu" "In2.Cu" "In3.Cu" "In4.Cu" "In5.Cu" "In6.Cu"
			"In7.Cu" "In8.Cu" "In9.Cu" "In10.Cu" "In11.Cu" "In12.Cu" "In13.Cu" "In14.Cu"
			"In15.Cu" "In16.Cu"
		)
		(hatch none 0.5)
		(connect_pads
			(clearance 0)
		)
		(min_thickness 0.25)
		(keepout
			(tracks not_allowed)
			(vias allowed)
			(pads allowed)
			(copperpour not_allowed)
			(footprints allowed)
		)
		(placement
			(enabled no)
			(sheetname "")
		)
		(fill
			(thermal_gap 0.5)
			(thermal_bridge_width 0.5)
			(island_removal_mode 0)
		)
		(polygon
			(pts
				(arc
					(start 347.772482 -288.818828)
					(mid 347.752798 -288.866238)
					(end 347.746066 -288.917126)
				)
				(arc
					(start 347.746066 -288.917126)
					(mid 347.803722 -289.05632)
					(end 347.942916 -289.113976)
				)
				(arc
					(start 347.942916 -289.113976)
					(mid 348.041347 -289.08756)
					(end 348.11335 -289.015424)
				)
				(arc
					(start 348.58325 -288.201354)
					(mid 348.602934 -288.153944)
					(end 348.609666 -288.103056)
				)
				(arc
					(start 348.609666 -288.103056)
					(mid 348.55201 -287.963862)
					(end 348.412816 -287.906206)
				)
				(arc
					(start 348.412816 -287.906206)
					(mid 348.314385 -287.932622)
					(end 348.242382 -288.004758)
				)
			)
		)
	)
	(zone
		(layers "F.Cu" "B.Cu" "In1.Cu" "In2.Cu" "In3.Cu" "In4.Cu" "In5.Cu" "In6.Cu"
			"In7.Cu" "In8.Cu" "In9.Cu" "In10.Cu" "In11.Cu" "In12.Cu" "In13.Cu" "In14.Cu"
			"In15.Cu" "In16.Cu"
		)
		(hatch none 0.5)
		(connect_pads
			(clearance 0)
		)
		(min_thickness 0.25)
		(keepout
			(tracks not_allowed)
			(vias allowed)
			(pads allowed)
			(copperpour not_allowed)
			(footprints allowed)
		)
		(placement
			(enabled no)
			(sheetname "")
		)
		(fill
			(thermal_gap 0.5)
			(thermal_bridge_width 0.5)
			(island_removal_mode 0)
		)
		(polygon
			(pts
				(arc
					(start 371.65661 -225.203258)
					(mid 370.99875 -225.203258)
					(end 371.65661 -225.203258)
				)
			)
		)
	)
	(zone
		(layers "F.Cu" "B.Cu" "In1.Cu" "In2.Cu" "In3.Cu" "In4.Cu" "In5.Cu" "In6.Cu"
			"In7.Cu" "In8.Cu" "In9.Cu" "In10.Cu" "In11.Cu" "In12.Cu" "In13.Cu" "In14.Cu"
			"In15.Cu" "In16.Cu"
		)
		(hatch none 0.5)
		(connect_pads
			(clearance 0)
		)
		(min_thickness 0.25)
		(keepout
			(tracks not_allowed)
			(vias allowed)
			(pads allowed)
			(copperpour not_allowed)
			(footprints allowed)
		)
		(placement
			(enabled no)
			(sheetname "")
		)
		(fill
			(thermal_gap 0.5)
			(thermal_bridge_width 0.5)
			(island_removal_mode 0)
		)
		(polygon
			(pts
				(arc
					(start 89.225882 -215.436704)
					(mid 89.883742 -215.436704)
					(end 89.225882 -215.436704)
				)
			)
		)
	)
	(zone
		(layers "F.Cu" "B.Cu" "In1.Cu" "In2.Cu" "In3.Cu" "In4.Cu" "In5.Cu" "In6.Cu"
			"In7.Cu" "In8.Cu" "In9.Cu" "In10.Cu" "In11.Cu" "In12.Cu" "In13.Cu" "In14.Cu"
			"In15.Cu" "In16.Cu"
		)
		(hatch none 0.5)
		(connect_pads
			(clearance 0)
		)
		(min_thickness 0.25)
		(keepout
			(tracks not_allowed)
			(vias allowed)
			(pads allowed)
			(copperpour not_allowed)
			(footprints allowed)
		)
		(placement
			(enabled no)
			(sheetname "")
		)
		(fill
			(thermal_gap 0.5)
			(thermal_bridge_width 0.5)
			(island_removal_mode 0)
		)
		(polygon
			(pts
				(arc
					(start 310.106568 -403.502876)
					(mid 309.725568 -403.883876)
					(end 310.106568 -404.264876)
				)
				(arc
					(start 310.970168 -404.264876)
					(mid 311.351168 -403.883876)
					(end 310.970168 -403.502876)
				)
			)
		)
	)
	(zone
		(layers "F.Cu" "B.Cu" "In1.Cu" "In2.Cu" "In3.Cu" "In4.Cu" "In5.Cu" "In6.Cu"
			"In7.Cu" "In8.Cu" "In9.Cu" "In10.Cu" "In11.Cu" "In12.Cu" "In13.Cu" "In14.Cu"
			"In15.Cu" "In16.Cu"
		)
		(hatch none 0.5)
		(connect_pads
			(clearance 0)
		)
		(min_thickness 0.25)
		(keepout
			(tracks not_allowed)
			(vias allowed)
			(pads allowed)
			(copperpour not_allowed)
			(footprints allowed)
		)
		(placement
			(enabled no)
			(sheetname "")
		)
		(fill
			(thermal_gap 0.5)
			(thermal_bridge_width 0.5)
			(island_removal_mode 0)
		)
		(polygon
			(pts
				(arc
					(start 367.427764 -217.878406)
					(mid 366.769904 -217.878406)
					(end 367.427764 -217.878406)
				)
			)
		)
	)
	(zone
		(layers "F.Cu" "B.Cu" "In1.Cu" "In2.Cu" "In3.Cu" "In4.Cu" "In5.Cu" "In6.Cu"
			"In7.Cu" "In8.Cu" "In9.Cu" "In10.Cu" "In11.Cu" "In12.Cu" "In13.Cu" "In14.Cu"
			"In15.Cu" "In16.Cu"
		)
		(hatch none 0.5)
		(connect_pads
			(clearance 0)
		)
		(min_thickness 0.25)
		(keepout
			(tracks not_allowed)
			(vias allowed)
			(pads allowed)
			(copperpour not_allowed)
			(footprints allowed)
		)
		(placement
			(enabled no)
			(sheetname "")
		)
		(fill
			(thermal_gap 0.5)
			(thermal_bridge_width 0.5)
			(island_removal_mode 0)
		)
		(polygon
			(pts
				(arc
					(start 125.518164 -289.807142)
					(mid 126.176024 -289.807142)
					(end 125.518164 -289.807142)
				)
			)
		)
	)
	(zone
		(layers "F.Cu" "B.Cu" "In1.Cu" "In2.Cu" "In3.Cu" "In4.Cu" "In5.Cu" "In6.Cu"
			"In7.Cu" "In8.Cu" "In9.Cu" "In10.Cu" "In11.Cu" "In12.Cu" "In13.Cu" "In14.Cu"
			"In15.Cu" "In16.Cu"
		)
		(hatch none 0.5)
		(connect_pads
			(clearance 0)
		)
		(min_thickness 0.25)
		(keepout
			(tracks not_allowed)
			(vias allowed)
			(pads allowed)
			(copperpour not_allowed)
			(footprints allowed)
		)
		(placement
			(enabled no)
			(sheetname "")
		)
		(fill
			(thermal_gap 0.5)
			(thermal_bridge_width 0.5)
			(island_removal_mode 0)
		)
		(polygon
			(pts
				(arc
					(start 629.377202 -438.56529)
					(mid 625.186202 -438.56529)
					(end 629.377202 -438.56529)
				)
			)
		)
	)
	(zone
		(layers "F.Cu" "B.Cu" "In1.Cu" "In2.Cu" "In3.Cu" "In4.Cu" "In5.Cu" "In6.Cu"
			"In7.Cu" "In8.Cu" "In9.Cu" "In10.Cu" "In11.Cu" "In12.Cu" "In13.Cu" "In14.Cu"
			"In15.Cu" "In16.Cu"
		)
		(hatch none 0.5)
		(connect_pads
			(clearance 0)
		)
		(min_thickness 0.25)
		(keepout
			(tracks not_allowed)
			(vias allowed)
			(pads allowed)
			(copperpour not_allowed)
			(footprints allowed)
		)
		(placement
			(enabled no)
			(sheetname "")
		)
		(fill
			(thermal_gap 0.5)
			(thermal_bridge_width 0.5)
			(island_removal_mode 0)
		)
		(polygon
			(pts
				(arc
					(start 377.765564 -217.878406)
					(mid 377.107704 -217.878406)
					(end 377.765564 -217.878406)
				)
			)
		)
	)
	(zone
		(layers "F.Cu" "B.Cu" "In1.Cu" "In2.Cu" "In3.Cu" "In4.Cu" "In5.Cu" "In6.Cu"
			"In7.Cu" "In8.Cu" "In9.Cu" "In10.Cu" "In11.Cu" "In12.Cu" "In13.Cu" "In14.Cu"
			"In15.Cu" "In16.Cu"
		)
		(hatch none 0.5)
		(connect_pads
			(clearance 0)
		)
		(min_thickness 0.25)
		(keepout
			(tracks not_allowed)
			(vias allowed)
			(pads allowed)
			(copperpour not_allowed)
			(footprints allowed)
		)
		(placement
			(enabled no)
			(sheetname "")
		)
		(fill
			(thermal_gap 0.5)
			(thermal_bridge_width 0.5)
			(island_removal_mode 0)
		)
		(polygon
			(pts
				(arc
					(start 89.194894 -279.767284)
					(mid 88.998044 -279.964134)
					(end 89.194894 -280.160984)
				)
				(arc
					(start 90.134694 -280.160984)
					(mid 90.331544 -279.964134)
					(end 90.134694 -279.767284)
				)
			)
		)
	)
	(zone
		(layers "F.Cu" "B.Cu" "In1.Cu" "In2.Cu" "In3.Cu" "In4.Cu" "In5.Cu" "In6.Cu"
			"In7.Cu" "In8.Cu" "In9.Cu" "In10.Cu" "In11.Cu" "In12.Cu" "In13.Cu" "In14.Cu"
			"In15.Cu" "In16.Cu"
		)
		(hatch none 0.5)
		(connect_pads
			(clearance 0)
		)
		(min_thickness 0.25)
		(keepout
			(tracks not_allowed)
			(vias allowed)
			(pads allowed)
			(copperpour not_allowed)
			(footprints allowed)
		)
		(placement
			(enabled no)
			(sheetname "")
		)
		(fill
			(thermal_gap 0.5)
			(thermal_bridge_width 0.5)
			(island_removal_mode 0)
		)
		(polygon
			(pts
				(arc
					(start 106.41076 -277.424134)
					(mid 106.391076 -277.471544)
					(end 106.384344 -277.522432)
				)
				(arc
					(start 106.384344 -277.522432)
					(mid 106.442 -277.661626)
					(end 106.581194 -277.719282)
				)
				(arc
					(start 106.581194 -277.719282)
					(mid 106.679625 -277.692866)
					(end 106.751628 -277.62073)
				)
				(arc
					(start 107.221528 -276.80666)
					(mid 107.241212 -276.75925)
					(end 107.247944 -276.708362)
				)
				(arc
					(start 107.247944 -276.708362)
					(mid 107.190288 -276.569168)
					(end 107.051094 -276.511512)
				)
				(arc
					(start 107.051094 -276.511512)
					(mid 106.952663 -276.537928)
					(end 106.88066 -276.610064)
				)
			)
		)
	)
	(zone
		(layers "F.Cu" "B.Cu" "In1.Cu" "In2.Cu" "In3.Cu" "In4.Cu" "In5.Cu" "In6.Cu"
			"In7.Cu" "In8.Cu" "In9.Cu" "In10.Cu" "In11.Cu" "In12.Cu" "In13.Cu" "In14.Cu"
			"In15.Cu" "In16.Cu"
		)
		(hatch none 0.5)
		(connect_pads
			(clearance 0)
		)
		(min_thickness 0.25)
		(keepout
			(tracks not_allowed)
			(vias allowed)
			(pads allowed)
			(copperpour not_allowed)
			(footprints allowed)
		)
		(placement
			(enabled no)
			(sheetname "")
		)
		(fill
			(thermal_gap 0.5)
			(thermal_bridge_width 0.5)
			(island_removal_mode 0)
		)
		(polygon
			(pts
				(arc
					(start 122.148092 -214.720932)
					(mid 122.167776 -214.673522)
					(end 122.174508 -214.622634)
				)
				(arc
					(start 122.174508 -214.622634)
					(mid 122.116852 -214.48344)
					(end 121.977658 -214.425784)
				)
				(arc
					(start 121.977658 -214.425784)
					(mid 121.879227 -214.4522)
					(end 121.807224 -214.524336)
				)
				(arc
					(start 121.337578 -215.338406)
					(mid 121.317894 -215.385816)
					(end 121.311162 -215.436704)
				)
				(arc
					(start 121.311162 -215.436704)
					(mid 121.368818 -215.575898)
					(end 121.508012 -215.633554)
				)
				(arc
					(start 121.508012 -215.633554)
					(mid 121.606443 -215.607138)
					(end 121.678446 -215.535002)
				)
			)
		)
	)
	(zone
		(layers "F.Cu" "B.Cu" "In1.Cu" "In2.Cu" "In3.Cu" "In4.Cu" "In5.Cu" "In6.Cu"
			"In7.Cu" "In8.Cu" "In9.Cu" "In10.Cu" "In11.Cu" "In12.Cu" "In13.Cu" "In14.Cu"
			"In15.Cu" "In16.Cu"
		)
		(hatch none 0.5)
		(connect_pads
			(clearance 0)
		)
		(min_thickness 0.25)
		(keepout
			(tracks not_allowed)
			(vias allowed)
			(pads allowed)
			(copperpour not_allowed)
			(footprints allowed)
		)
		(placement
			(enabled no)
			(sheetname "")
		)
		(fill
			(thermal_gap 0.5)
			(thermal_bridge_width 0.5)
			(island_removal_mode 0)
		)
		(polygon
			(pts
				(arc
					(start 283.40304 -153.766012)
					(mid 272.38706 -153.766012)
					(end 283.40304 -153.766012)
				)
			)
		)
	)
	(zone
		(layers "F.Cu" "B.Cu" "In1.Cu" "In2.Cu" "In3.Cu" "In4.Cu" "In5.Cu" "In6.Cu"
			"In7.Cu" "In8.Cu" "In9.Cu" "In10.Cu" "In11.Cu" "In12.Cu" "In13.Cu" "In14.Cu"
			"In15.Cu" "In16.Cu"
		)
		(hatch none 0.5)
		(connect_pads
			(clearance 0)
		)
		(min_thickness 0.25)
		(keepout
			(tracks not_allowed)
			(vias allowed)
			(pads allowed)
			(copperpour not_allowed)
			(footprints allowed)
		)
		(placement
			(enabled no)
			(sheetname "")
		)
		(fill
			(thermal_gap 0.5)
			(thermal_bridge_width 0.5)
			(island_removal_mode 0)
		)
		(polygon
			(pts
				(arc
					(start 135.544814 -289.015424)
					(mid 135.616803 -289.087583)
					(end 135.715248 -289.113976)
				)
				(arc
					(start 135.715248 -289.113976)
					(mid 135.854442 -289.05632)
					(end 135.912098 -288.917126)
				)
				(arc
					(start 135.912098 -288.917126)
					(mid 135.905341 -288.866245)
					(end 135.885682 -288.818828)
				)
				(arc
					(start 135.415782 -288.004758)
					(mid 135.343793 -287.932599)
					(end 135.245348 -287.906206)
				)
				(arc
					(start 135.245348 -287.906206)
					(mid 135.106154 -287.963862)
					(end 135.048498 -288.103056)
				)
				(arc
					(start 135.048498 -288.103056)
					(mid 135.055255 -288.153937)
					(end 135.074914 -288.201354)
				)
			)
		)
	)
	(zone
		(layers "F.Cu" "B.Cu" "In1.Cu" "In2.Cu" "In3.Cu" "In4.Cu" "In5.Cu" "In6.Cu"
			"In7.Cu" "In8.Cu" "In9.Cu" "In10.Cu" "In11.Cu" "In12.Cu" "In13.Cu" "In14.Cu"
			"In15.Cu" "In16.Cu"
		)
		(hatch none 0.5)
		(connect_pads
			(clearance 0)
		)
		(min_thickness 0.25)
		(keepout
			(tracks not_allowed)
			(vias allowed)
			(pads allowed)
			(copperpour not_allowed)
			(footprints allowed)
		)
		(placement
			(enabled no)
			(sheetname "")
		)
		(fill
			(thermal_gap 0.5)
			(thermal_bridge_width 0.5)
			(island_removal_mode 0)
		)
		(polygon
			(pts
				(arc
					(start 351.531682 -288.818828)
					(mid 351.511998 -288.866238)
					(end 351.505266 -288.917126)
				)
				(arc
					(start 351.505266 -288.917126)
					(mid 351.562922 -289.05632)
					(end 351.702116 -289.113976)
				)
				(arc
					(start 351.702116 -289.113976)
					(mid 351.800547 -289.08756)
					(end 351.87255 -289.015424)
				)
				(arc
					(start 352.34245 -288.201354)
					(mid 352.362134 -288.153944)
					(end 352.368866 -288.103056)
				)
				(arc
					(start 352.368866 -288.103056)
					(mid 352.31121 -287.963862)
					(end 352.172016 -287.906206)
				)
				(arc
					(start 352.172016 -287.906206)
					(mid 352.073585 -287.932622)
					(end 352.001582 -288.004758)
				)
			)
		)
	)
	(zone
		(layers "F.Cu" "B.Cu" "In1.Cu" "In2.Cu" "In3.Cu" "In4.Cu" "In5.Cu" "In6.Cu"
			"In7.Cu" "In8.Cu" "In9.Cu" "In10.Cu" "In11.Cu" "In12.Cu" "In13.Cu" "In14.Cu"
			"In15.Cu" "In16.Cu"
		)
		(hatch none 0.5)
		(connect_pads
			(clearance 0)
		)
		(min_thickness 0.25)
		(keepout
			(tracks not_allowed)
			(vias allowed)
			(pads allowed)
			(copperpour not_allowed)
			(footprints allowed)
		)
		(placement
			(enabled no)
			(sheetname "")
		)
		(fill
			(thermal_gap 0.5)
			(thermal_bridge_width 0.5)
			(island_removal_mode 0)
		)
		(polygon
			(pts
				(arc
					(start 132.016754 -220.22181)
					(mid 131.944765 -220.149651)
					(end 131.84632 -220.123258)
				)
				(arc
					(start 131.84632 -220.123258)
					(mid 131.707126 -220.180914)
					(end 131.64947 -220.320108)
				)
				(arc
					(start 131.64947 -220.320108)
					(mid 131.656227 -220.370989)
					(end 131.675886 -220.418406)
				)
				(arc
					(start 132.145532 -221.232222)
					(mid 132.217521 -221.304381)
					(end 132.315966 -221.330774)
				)
				(arc
					(start 132.315966 -221.330774)
					(mid 132.45516 -221.273118)
					(end 132.512816 -221.133924)
				)
				(arc
					(start 132.512816 -221.133924)
					(mid 132.506059 -221.083043)
					(end 132.4864 -221.035626)
				)
			)
		)
	)
	(zone
		(layers "F.Cu" "B.Cu" "In1.Cu" "In2.Cu" "In3.Cu" "In4.Cu" "In5.Cu" "In6.Cu"
			"In7.Cu" "In8.Cu" "In9.Cu" "In10.Cu" "In11.Cu" "In12.Cu" "In13.Cu" "In14.Cu"
			"In15.Cu" "In16.Cu"
		)
		(hatch none 0.5)
		(connect_pads
			(clearance 0)
		)
		(min_thickness 0.25)
		(keepout
			(tracks not_allowed)
			(vias allowed)
			(pads allowed)
			(copperpour not_allowed)
			(footprints allowed)
		)
		(placement
			(enabled no)
			(sheetname "")
		)
		(fill
			(thermal_gap 0.5)
			(thermal_bridge_width 0.5)
			(island_removal_mode 0)
		)
		(polygon
			(pts
				(arc
					(start 101.712014 -288.818828)
					(mid 101.69233 -288.866238)
					(end 101.685598 -288.917126)
				)
				(arc
					(start 101.685598 -288.917126)
					(mid 101.743254 -289.05632)
					(end 101.882448 -289.113976)
				)
				(arc
					(start 101.882448 -289.113976)
					(mid 101.980879 -289.08756)
					(end 102.052882 -289.015424)
				)
				(arc
					(start 102.522782 -288.201354)
					(mid 102.542466 -288.153944)
					(end 102.549198 -288.103056)
				)
				(arc
					(start 102.549198 -288.103056)
					(mid 102.491542 -287.963862)
					(end 102.352348 -287.906206)
				)
				(arc
					(start 102.352348 -287.906206)
					(mid 102.253917 -287.932622)
					(end 102.181914 -288.004758)
				)
			)
		)
	)
	(zone
		(layers "F.Cu" "B.Cu" "In1.Cu" "In2.Cu" "In3.Cu" "In4.Cu" "In5.Cu" "In6.Cu"
			"In7.Cu" "In8.Cu" "In9.Cu" "In10.Cu" "In11.Cu" "In12.Cu" "In13.Cu" "In14.Cu"
			"In15.Cu" "In16.Cu"
		)
		(hatch none 0.5)
		(connect_pads
			(clearance 0)
		)
		(min_thickness 0.25)
		(keepout
			(tracks not_allowed)
			(vias allowed)
			(pads allowed)
			(copperpour not_allowed)
			(footprints allowed)
		)
		(placement
			(enabled no)
			(sheetname "")
		)
		(fill
			(thermal_gap 0.5)
			(thermal_bridge_width 0.5)
			(island_removal_mode 0)
		)
		(polygon
			(pts
				(arc
					(start 128.995678 -284.847538)
					(mid 128.337818 -284.847538)
					(end 128.995678 -284.847538)
				)
			)
		)
	)
	(zone
		(layers "F.Cu" "B.Cu" "In1.Cu" "In2.Cu" "In3.Cu" "In4.Cu" "In5.Cu" "In6.Cu"
			"In7.Cu" "In8.Cu" "In9.Cu" "In10.Cu" "In11.Cu" "In12.Cu" "In13.Cu" "In14.Cu"
			"In15.Cu" "In16.Cu"
		)
		(hatch none 0.5)
		(connect_pads
			(clearance 0)
		)
		(min_thickness 0.25)
		(keepout
			(tracks not_allowed)
			(vias allowed)
			(pads allowed)
			(copperpour not_allowed)
			(footprints allowed)
		)
		(placement
			(enabled no)
			(sheetname "")
		)
		(fill
			(thermal_gap 0.5)
			(thermal_bridge_width 0.5)
			(island_removal_mode 0)
		)
		(polygon
			(pts
				(arc
					(start 123.638564 -289.807142)
					(mid 124.296424 -289.807142)
					(end 123.638564 -289.807142)
				)
			)
		)
	)
	(zone
		(layers "F.Cu" "B.Cu" "In1.Cu" "In2.Cu" "In3.Cu" "In4.Cu" "In5.Cu" "In6.Cu"
			"In7.Cu" "In8.Cu" "In9.Cu" "In10.Cu" "In11.Cu" "In12.Cu" "In13.Cu" "In14.Cu"
			"In15.Cu" "In16.Cu"
		)
		(hatch none 0.5)
		(connect_pads
			(clearance 0)
		)
		(min_thickness 0.25)
		(keepout
			(tracks not_allowed)
			(vias allowed)
			(pads allowed)
			(copperpour not_allowed)
			(footprints allowed)
		)
		(placement
			(enabled no)
			(sheetname "")
		)
		(fill
			(thermal_gap 0.5)
			(thermal_bridge_width 0.5)
			(island_removal_mode 0)
		)
		(polygon
			(pts
				(arc
					(start 84.738718 -400.477228)
					(mid 84.357718 -400.858228)
					(end 84.738718 -401.239228)
				)
				(arc
					(start 85.602318 -401.239228)
					(mid 85.983318 -400.858228)
					(end 85.602318 -400.477228)
				)
			)
		)
	)
	(zone
		(layers "F.Cu" "B.Cu" "In1.Cu" "In2.Cu" "In3.Cu" "In4.Cu" "In5.Cu" "In6.Cu"
			"In7.Cu" "In8.Cu" "In9.Cu" "In10.Cu" "In11.Cu" "In12.Cu" "In13.Cu" "In14.Cu"
			"In15.Cu" "In16.Cu"
		)
		(hatch none 0.5)
		(connect_pads
			(clearance 0)
		)
		(min_thickness 0.25)
		(keepout
			(tracks not_allowed)
			(vias allowed)
			(pads allowed)
			(copperpour not_allowed)
			(footprints allowed)
		)
		(placement
			(enabled no)
			(sheetname "")
		)
		(fill
			(thermal_gap 0.5)
			(thermal_bridge_width 0.5)
			(island_removal_mode 0)
		)
		(polygon
			(pts
				(arc
					(start 134.054342 -217.064336)
					(mid 133.396482 -217.064336)
					(end 134.054342 -217.064336)
				)
			)
		)
	)
	(zone
		(layers "F.Cu" "B.Cu" "In1.Cu" "In2.Cu" "In3.Cu" "In4.Cu" "In5.Cu" "In6.Cu"
			"In7.Cu" "In8.Cu" "In9.Cu" "In10.Cu" "In11.Cu" "In12.Cu" "In13.Cu" "In14.Cu"
			"In15.Cu" "In16.Cu"
		)
		(hatch none 0.5)
		(connect_pads
			(clearance 0)
		)
		(min_thickness 0.25)
		(keepout
			(tracks not_allowed)
			(vias allowed)
			(pads allowed)
			(copperpour not_allowed)
			(footprints allowed)
		)
		(placement
			(enabled no)
			(sheetname "")
		)
		(fill
			(thermal_gap 0.5)
			(thermal_bridge_width 0.5)
			(island_removal_mode 0)
		)
		(polygon
			(pts
				(arc
					(start 362.25861 -225.203258)
					(mid 361.60075 -225.203258)
					(end 362.25861 -225.203258)
				)
			)
		)
	)
	(zone
		(layers "F.Cu" "B.Cu" "In1.Cu" "In2.Cu" "In3.Cu" "In4.Cu" "In5.Cu" "In6.Cu"
			"In7.Cu" "In8.Cu" "In9.Cu" "In10.Cu" "In11.Cu" "In12.Cu" "In13.Cu" "In14.Cu"
			"In15.Cu" "In16.Cu"
		)
		(hatch none 0.5)
		(connect_pads
			(clearance 0)
		)
		(min_thickness 0.25)
		(keepout
			(tracks not_allowed)
			(vias allowed)
			(pads allowed)
			(copperpour not_allowed)
			(footprints allowed)
		)
		(placement
			(enabled no)
			(sheetname "")
		)
		(fill
			(thermal_gap 0.5)
			(thermal_bridge_width 0.5)
			(island_removal_mode 0)
		)
		(polygon
			(pts
				(arc
					(start 376.197114 -223.67367)
					(mid 376.216798 -223.62626)
					(end 376.22353 -223.575372)
				)
				(arc
					(start 376.22353 -223.575372)
					(mid 376.165874 -223.436178)
					(end 376.02668 -223.378522)
				)
				(arc
					(start 376.02668 -223.378522)
					(mid 375.928249 -223.404938)
					(end 375.856246 -223.477074)
				)
				(arc
					(start 375.3866 -224.291144)
					(mid 375.366916 -224.338554)
					(end 375.360184 -224.389442)
				)
				(arc
					(start 375.360184 -224.389442)
					(mid 375.41784 -224.528636)
					(end 375.557034 -224.586292)
				)
				(arc
					(start 375.557034 -224.586292)
					(mid 375.655465 -224.559876)
					(end 375.727468 -224.48774)
				)
			)
		)
	)
	(zone
		(layers "F.Cu" "B.Cu" "In1.Cu" "In2.Cu" "In3.Cu" "In4.Cu" "In5.Cu" "In6.Cu"
			"In7.Cu" "In8.Cu" "In9.Cu" "In10.Cu" "In11.Cu" "In12.Cu" "In13.Cu" "In14.Cu"
			"In15.Cu" "In16.Cu"
		)
		(hatch none 0.5)
		(connect_pads
			(clearance 0)
		)
		(min_thickness 0.25)
		(keepout
			(tracks not_allowed)
			(vias allowed)
			(pads allowed)
			(copperpour not_allowed)
			(footprints allowed)
		)
		(placement
			(enabled no)
			(sheetname "")
		)
		(fill
			(thermal_gap 0.5)
			(thermal_bridge_width 0.5)
			(island_removal_mode 0)
		)
		(polygon
			(pts
				(arc
					(start 12.476226 -105.53827)
					(mid 12.095226 -105.15727)
					(end 11.714226 -105.53827)
				)
				(arc
					(start 11.714226 -106.40187)
					(mid 12.095226 -106.78287)
					(end 12.476226 -106.40187)
				)
			)
		)
	)
	(zone
		(layers "F.Cu" "B.Cu" "In1.Cu" "In2.Cu" "In3.Cu" "In4.Cu" "In5.Cu" "In6.Cu"
			"In7.Cu" "In8.Cu" "In9.Cu" "In10.Cu" "In11.Cu" "In12.Cu" "In13.Cu" "In14.Cu"
			"In15.Cu" "In16.Cu"
		)
		(hatch none 0.5)
		(connect_pads
			(clearance 0)
		)
		(min_thickness 0.25)
		(keepout
			(tracks not_allowed)
			(vias allowed)
			(pads allowed)
			(copperpour not_allowed)
			(footprints allowed)
		)
		(placement
			(enabled no)
			(sheetname "")
		)
		(fill
			(thermal_gap 0.5)
			(thermal_bridge_width 0.5)
			(island_removal_mode 0)
		)
		(polygon
			(pts
				(arc
					(start 351.762314 -220.418152)
					(mid 351.781998 -220.370742)
					(end 351.78873 -220.319854)
				)
				(arc
					(start 351.78873 -220.319854)
					(mid 351.731074 -220.18066)
					(end 351.59188 -220.123004)
				)
				(arc
					(start 351.59188 -220.123004)
					(mid 351.493449 -220.14942)
					(end 351.421446 -220.221556)
				)
				(arc
					(start 350.9518 -221.035626)
					(mid 350.932116 -221.083036)
					(end 350.925384 -221.133924)
				)
				(arc
					(start 350.925384 -221.133924)
					(mid 350.98304 -221.273118)
					(end 351.122234 -221.330774)
				)
				(arc
					(start 351.122234 -221.330774)
					(mid 351.220665 -221.304358)
					(end 351.292668 -221.232222)
				)
			)
		)
	)
	(zone
		(layers "F.Cu" "B.Cu" "In1.Cu" "In2.Cu" "In3.Cu" "In4.Cu" "In5.Cu" "In6.Cu"
			"In7.Cu" "In8.Cu" "In9.Cu" "In10.Cu" "In11.Cu" "In12.Cu" "In13.Cu" "In14.Cu"
			"In15.Cu" "In16.Cu"
		)
		(hatch none 0.5)
		(connect_pads
			(clearance 0)
		)
		(min_thickness 0.25)
		(keepout
			(tracks not_allowed)
			(vias allowed)
			(pads allowed)
			(copperpour not_allowed)
			(footprints allowed)
		)
		(placement
			(enabled no)
			(sheetname "")
		)
		(fill
			(thermal_gap 0.5)
			(thermal_bridge_width 0.5)
			(island_removal_mode 0)
		)
		(polygon
			(pts
				(xy 468.100156 -372.40845) (xy 468.100156 -377.40844) (xy 467.795356 -377.10364) (xy 467.795356 -372.71325)
			)
		)
	)
	(zone
		(layers "F.Cu" "B.Cu" "In1.Cu" "In2.Cu" "In3.Cu" "In4.Cu" "In5.Cu" "In6.Cu"
			"In7.Cu" "In8.Cu" "In9.Cu" "In10.Cu" "In11.Cu" "In12.Cu" "In13.Cu" "In14.Cu"
			"In15.Cu" "In16.Cu"
		)
		(hatch none 0.5)
		(connect_pads
			(clearance 0)
		)
		(min_thickness 0.25)
		(keepout
			(tracks not_allowed)
			(vias allowed)
			(pads allowed)
			(copperpour not_allowed)
			(footprints allowed)
		)
		(placement
			(enabled no)
			(sheetname "")
		)
		(fill
			(thermal_gap 0.5)
			(thermal_bridge_width 0.5)
			(island_removal_mode 0)
		)
		(polygon
			(pts
				(arc
					(start 108.161582 -274.982432)
					(mid 108.089593 -274.910273)
					(end 107.991148 -274.88388)
				)
				(arc
					(start 107.991148 -274.88388)
					(mid 107.851954 -274.941536)
					(end 107.794298 -275.08073)
				)
				(arc
					(start 107.794298 -275.08073)
					(mid 107.801055 -275.131611)
					(end 107.820714 -275.179028)
				)
				(arc
					(start 108.290614 -275.993098)
					(mid 108.362603 -276.065257)
					(end 108.461048 -276.09165)
				)
				(arc
					(start 108.461048 -276.09165)
					(mid 108.600242 -276.033994)
					(end 108.657898 -275.8948)
				)
				(arc
					(start 108.657898 -275.8948)
					(mid 108.651141 -275.843919)
					(end 108.631482 -275.796502)
				)
			)
		)
	)
	(zone
		(layers "F.Cu" "B.Cu" "In1.Cu" "In2.Cu" "In3.Cu" "In4.Cu" "In5.Cu" "In6.Cu"
			"In7.Cu" "In8.Cu" "In9.Cu" "In10.Cu" "In11.Cu" "In12.Cu" "In13.Cu" "In14.Cu"
			"In15.Cu" "In16.Cu"
		)
		(hatch none 0.5)
		(connect_pads
			(clearance 0)
		)
		(min_thickness 0.25)
		(keepout
			(tracks not_allowed)
			(vias allowed)
			(pads allowed)
			(copperpour not_allowed)
			(footprints allowed)
		)
		(placement
			(enabled no)
			(sheetname "")
		)
		(fill
			(thermal_gap 0.5)
			(thermal_bridge_width 0.5)
			(island_removal_mode 0)
		)
		(polygon
			(pts
				(arc
					(start 378.705364 -224.389442)
					(mid 378.047504 -224.389442)
					(end 378.705364 -224.389442)
				)
			)
		)
	)
	(zone
		(layers "F.Cu" "B.Cu" "In1.Cu" "In2.Cu" "In3.Cu" "In4.Cu" "In5.Cu" "In6.Cu"
			"In7.Cu" "In8.Cu" "In9.Cu" "In10.Cu" "In11.Cu" "In12.Cu" "In13.Cu" "In14.Cu"
			"In15.Cu" "In16.Cu"
		)
		(hatch none 0.5)
		(connect_pads
			(clearance 0)
		)
		(min_thickness 0.25)
		(keepout
			(tracks not_allowed)
			(vias allowed)
			(pads allowed)
			(copperpour not_allowed)
			(footprints allowed)
		)
		(placement
			(enabled no)
			(sheetname "")
		)
		(fill
			(thermal_gap 0.5)
			(thermal_bridge_width 0.5)
			(island_removal_mode 0)
		)
		(polygon
			(pts
				(arc
					(start 339.343492 -281.59202)
					(mid 338.685632 -281.59202)
					(end 339.343492 -281.59202)
				)
			)
		)
	)
	(zone
		(layers "F.Cu" "B.Cu" "In1.Cu" "In2.Cu" "In3.Cu" "In4.Cu" "In5.Cu" "In6.Cu"
			"In7.Cu" "In8.Cu" "In9.Cu" "In10.Cu" "In11.Cu" "In12.Cu" "In13.Cu" "In14.Cu"
			"In15.Cu" "In16.Cu"
		)
		(hatch none 0.5)
		(connect_pads
			(clearance 0)
		)
		(min_thickness 0.25)
		(keepout
			(tracks not_allowed)
			(vias allowed)
			(pads allowed)
			(copperpour not_allowed)
			(footprints allowed)
		)
		(placement
			(enabled no)
			(sheetname "")
		)
		(fill
			(thermal_gap 0.5)
			(thermal_bridge_width 0.5)
			(island_removal_mode 0)
		)
		(polygon
			(pts
				(arc
					(start 121.289064 -285.661354)
					(mid 121.946924 -285.661354)
					(end 121.289064 -285.661354)
				)
			)
		)
	)
	(zone
		(layers "F.Cu" "B.Cu" "In1.Cu" "In2.Cu" "In3.Cu" "In4.Cu" "In5.Cu" "In6.Cu"
			"In7.Cu" "In8.Cu" "In9.Cu" "In10.Cu" "In11.Cu" "In12.Cu" "In13.Cu" "In14.Cu"
			"In15.Cu" "In16.Cu"
		)
		(hatch none 0.5)
		(connect_pads
			(clearance 0)
		)
		(min_thickness 0.25)
		(keepout
			(tracks not_allowed)
			(vias allowed)
			(pads allowed)
			(copperpour not_allowed)
			(footprints allowed)
		)
		(placement
			(enabled no)
			(sheetname "")
		)
		(fill
			(thermal_gap 0.5)
			(thermal_bridge_width 0.5)
			(island_removal_mode 0)
		)
		(polygon
			(pts
				(arc
					(start 374.897904 -288.005012)
					(mid 374.825915 -287.932853)
					(end 374.72747 -287.90646)
				)
				(arc
					(start 374.72747 -287.90646)
					(mid 374.588276 -287.964116)
					(end 374.53062 -288.10331)
				)
				(arc
					(start 374.53062 -288.10331)
					(mid 374.537377 -288.154191)
					(end 374.557036 -288.201608)
				)
				(arc
					(start 375.026682 -289.015424)
					(mid 375.098671 -289.087583)
					(end 375.197116 -289.113976)
				)
				(arc
					(start 375.197116 -289.113976)
					(mid 375.33631 -289.05632)
					(end 375.393966 -288.917126)
				)
				(arc
					(start 375.393966 -288.917126)
					(mid 375.387209 -288.866245)
					(end 375.36755 -288.818828)
				)
			)
		)
	)
	(zone
		(layers "F.Cu" "B.Cu" "In1.Cu" "In2.Cu" "In3.Cu" "In4.Cu" "In5.Cu" "In6.Cu"
			"In7.Cu" "In8.Cu" "In9.Cu" "In10.Cu" "In11.Cu" "In12.Cu" "In13.Cu" "In14.Cu"
			"In15.Cu" "In16.Cu"
		)
		(hatch none 0.5)
		(connect_pads
			(clearance 0)
		)
		(min_thickness 0.25)
		(keepout
			(tracks not_allowed)
			(vias allowed)
			(pads allowed)
			(copperpour not_allowed)
			(footprints allowed)
		)
		(placement
			(enabled no)
			(sheetname "")
		)
		(fill
			(thermal_gap 0.5)
			(thermal_bridge_width 0.5)
			(island_removal_mode 0)
		)
		(polygon
			(pts
				(arc
					(start 97.482914 -281.493722)
					(mid 97.46323 -281.541132)
					(end 97.456498 -281.59202)
				)
				(arc
					(start 97.456498 -281.59202)
					(mid 97.514154 -281.731214)
					(end 97.653348 -281.78887)
				)
				(arc
					(start 97.653348 -281.78887)
					(mid 97.751779 -281.762454)
					(end 97.823782 -281.690318)
				)
				(arc
					(start 98.293682 -280.876248)
					(mid 98.313366 -280.828838)
					(end 98.320098 -280.77795)
				)
				(arc
					(start 98.320098 -280.77795)
					(mid 98.262442 -280.638756)
					(end 98.123248 -280.5811)
				)
				(arc
					(start 98.123248 -280.5811)
					(mid 98.024817 -280.607516)
					(end 97.952814 -280.679652)
				)
			)
		)
	)
	(zone
		(layers "F.Cu" "B.Cu" "In1.Cu" "In2.Cu" "In3.Cu" "In4.Cu" "In5.Cu" "In6.Cu"
			"In7.Cu" "In8.Cu" "In9.Cu" "In10.Cu" "In11.Cu" "In12.Cu" "In13.Cu" "In14.Cu"
			"In15.Cu" "In16.Cu"
		)
		(hatch none 0.5)
		(connect_pads
			(clearance 0)
		)
		(min_thickness 0.25)
		(keepout
			(tracks not_allowed)
			(vias allowed)
			(pads allowed)
			(copperpour not_allowed)
			(footprints allowed)
		)
		(placement
			(enabled no)
			(sheetname "")
		)
		(fill
			(thermal_gap 0.5)
			(thermal_bridge_width 0.5)
			(island_removal_mode 0)
		)
		(polygon
			(pts
				(arc
					(start 352.030792 -280.778204)
					(mid 351.372932 -280.778204)
					(end 352.030792 -280.778204)
				)
			)
		)
	)
	(zone
		(layers "F.Cu" "B.Cu" "In1.Cu" "In2.Cu" "In3.Cu" "In4.Cu" "In5.Cu" "In6.Cu"
			"In7.Cu" "In8.Cu" "In9.Cu" "In10.Cu" "In11.Cu" "In12.Cu" "In13.Cu" "In14.Cu"
			"In15.Cu" "In16.Cu"
		)
		(hatch none 0.5)
		(connect_pads
			(clearance 0)
		)
		(min_thickness 0.25)
		(keepout
			(tracks not_allowed)
			(vias allowed)
			(pads allowed)
			(copperpour not_allowed)
			(footprints allowed)
		)
		(placement
			(enabled no)
			(sheetname "")
		)
		(fill
			(thermal_gap 0.5)
			(thermal_bridge_width 0.5)
			(island_removal_mode 0)
		)
		(polygon
			(pts
				(arc
					(start 357.401622 -220.22181)
					(mid 357.329633 -220.149651)
					(end 357.231188 -220.123258)
				)
				(arc
					(start 357.231188 -220.123258)
					(mid 357.091994 -220.180914)
					(end 357.034338 -220.320108)
				)
				(arc
					(start 357.034338 -220.320108)
					(mid 357.041095 -220.370989)
					(end 357.060754 -220.418406)
				)
				(arc
					(start 357.5304 -221.232222)
					(mid 357.602389 -221.304381)
					(end 357.700834 -221.330774)
				)
				(arc
					(start 357.700834 -221.330774)
					(mid 357.840028 -221.273118)
					(end 357.897684 -221.133924)
				)
				(arc
					(start 357.897684 -221.133924)
					(mid 357.890927 -221.083043)
					(end 357.871268 -221.035626)
				)
			)
		)
	)
	(zone
		(layers "F.Cu" "B.Cu" "In1.Cu" "In2.Cu" "In3.Cu" "In4.Cu" "In5.Cu" "In6.Cu"
			"In7.Cu" "In8.Cu" "In9.Cu" "In10.Cu" "In11.Cu" "In12.Cu" "In13.Cu" "In14.Cu"
			"In15.Cu" "In16.Cu"
		)
		(hatch none 0.5)
		(connect_pads
			(clearance 0)
		)
		(min_thickness 0.25)
		(keepout
			(tracks not_allowed)
			(vias allowed)
			(pads allowed)
			(copperpour not_allowed)
			(footprints allowed)
		)
		(placement
			(enabled no)
			(sheetname "")
		)
		(fill
			(thermal_gap 0.5)
			(thermal_bridge_width 0.5)
			(island_removal_mode 0)
		)
		(polygon
			(pts
				(arc
					(start 338.403692 -279.964134)
					(mid 337.745832 -279.964134)
					(end 338.403692 -279.964134)
				)
			)
		)
	)
	(zone
		(layers "F.Cu" "B.Cu" "In1.Cu" "In2.Cu" "In3.Cu" "In4.Cu" "In5.Cu" "In6.Cu"
			"In7.Cu" "In8.Cu" "In9.Cu" "In10.Cu" "In11.Cu" "In12.Cu" "In13.Cu" "In14.Cu"
			"In15.Cu" "In16.Cu"
		)
		(hatch none 0.5)
		(connect_pads
			(clearance 0)
		)
		(min_thickness 0.25)
		(keepout
			(tracks not_allowed)
			(vias allowed)
			(pads allowed)
			(copperpour not_allowed)
			(footprints allowed)
		)
		(placement
			(enabled no)
			(sheetname "")
		)
		(fill
			(thermal_gap 0.5)
			(thermal_bridge_width 0.5)
			(island_removal_mode 0)
		)
		(polygon
			(pts
				(xy 844.521806 -388.695946) (xy 839.52207 -388.695946) (xy 839.82687 -388.391146) (xy 844.217006 -388.391146)
			)
		)
	)
	(zone
		(layers "F.Cu" "B.Cu" "In1.Cu" "In2.Cu" "In3.Cu" "In4.Cu" "In5.Cu" "In6.Cu"
			"In7.Cu" "In8.Cu" "In9.Cu" "In10.Cu" "In11.Cu" "In12.Cu" "In13.Cu" "In14.Cu"
			"In15.Cu" "In16.Cu"
		)
		(hatch none 0.5)
		(connect_pads
			(clearance 0)
		)
		(min_thickness 0.25)
		(keepout
			(tracks not_allowed)
			(vias allowed)
			(pads allowed)
			(copperpour not_allowed)
			(footprints allowed)
		)
		(placement
			(enabled no)
			(sheetname "")
		)
		(fill
			(thermal_gap 0.5)
			(thermal_bridge_width 0.5)
			(island_removal_mode 0)
		)
		(polygon
			(pts
				(arc
					(start 92.662756 -297.515026)
					(mid 88.21674 -297.515026)
					(end 92.662756 -297.515026)
				)
			)
		)
	)
	(zone
		(layers "F.Cu" "B.Cu" "In1.Cu" "In2.Cu" "In3.Cu" "In4.Cu" "In5.Cu" "In6.Cu"
			"In7.Cu" "In8.Cu" "In9.Cu" "In10.Cu" "In11.Cu" "In12.Cu" "In13.Cu" "In14.Cu"
			"In15.Cu" "In16.Cu"
		)
		(hatch none 0.5)
		(connect_pads
			(clearance 0)
		)
		(min_thickness 0.25)
		(keepout
			(tracks not_allowed)
			(vias allowed)
			(pads allowed)
			(copperpour not_allowed)
			(footprints allowed)
		)
		(placement
			(enabled no)
			(sheetname "")
		)
		(fill
			(thermal_gap 0.5)
			(thermal_bridge_width 0.5)
			(island_removal_mode 0)
		)
		(polygon
			(pts
				(arc
					(start 89.2556 -217.780108)
					(mid 89.183611 -217.707949)
					(end 89.085166 -217.681556)
				)
				(arc
					(start 89.085166 -217.681556)
					(mid 88.945972 -217.739212)
					(end 88.888316 -217.878406)
				)
				(arc
					(start 88.888316 -217.878406)
					(mid 88.895073 -217.929287)
					(end 88.914732 -217.976704)
				)
				(arc
					(start 89.384378 -218.79052)
					(mid 89.456367 -218.862679)
					(end 89.554812 -218.889072)
				)
				(arc
					(start 89.554812 -218.889072)
					(mid 89.694006 -218.831416)
					(end 89.751662 -218.692222)
				)
				(arc
					(start 89.751662 -218.692222)
					(mid 89.744905 -218.641341)
					(end 89.725246 -218.593924)
				)
			)
		)
	)
	(zone
		(layers "F.Cu" "B.Cu" "In1.Cu" "In2.Cu" "In3.Cu" "In4.Cu" "In5.Cu" "In6.Cu"
			"In7.Cu" "In8.Cu" "In9.Cu" "In10.Cu" "In11.Cu" "In12.Cu" "In13.Cu" "In14.Cu"
			"In15.Cu" "In16.Cu"
		)
		(hatch none 0.5)
		(connect_pads
			(clearance 0)
		)
		(min_thickness 0.25)
		(keepout
			(tracks not_allowed)
			(vias allowed)
			(pads allowed)
			(copperpour not_allowed)
			(footprints allowed)
		)
		(placement
			(enabled no)
			(sheetname "")
		)
		(fill
			(thermal_gap 0.5)
			(thermal_bridge_width 0.5)
			(island_removal_mode 0)
		)
		(polygon
			(pts
				(arc
					(start 31.621476 -4.581652)
					(mid 31.240476 -4.962652)
					(end 31.621476 -5.343652)
				)
				(arc
					(start 32.485076 -5.343652)
					(mid 32.866076 -4.962652)
					(end 32.485076 -4.581652)
				)
			)
		)
	)
	(zone
		(layers "F.Cu" "B.Cu" "In1.Cu" "In2.Cu" "In3.Cu" "In4.Cu" "In5.Cu" "In6.Cu"
			"In7.Cu" "In8.Cu" "In9.Cu" "In10.Cu" "In11.Cu" "In12.Cu" "In13.Cu" "In14.Cu"
			"In15.Cu" "In16.Cu"
		)
		(hatch none 0.5)
		(connect_pads
			(clearance 0)
		)
		(min_thickness 0.25)
		(keepout
			(tracks not_allowed)
			(vias allowed)
			(pads allowed)
			(copperpour not_allowed)
			(footprints allowed)
		)
		(placement
			(enabled no)
			(sheetname "")
		)
		(fill
			(thermal_gap 0.5)
			(thermal_bridge_width 0.5)
			(island_removal_mode 0)
		)
		(polygon
			(pts
				(arc
					(start 375.056146 -288.103056)
					(mid 374.398286 -288.103056)
					(end 375.056146 -288.103056)
				)
			)
		)
	)
	(zone
		(layers "F.Cu" "B.Cu" "In1.Cu" "In2.Cu" "In3.Cu" "In4.Cu" "In5.Cu" "In6.Cu"
			"In7.Cu" "In8.Cu" "In9.Cu" "In10.Cu" "In11.Cu" "In12.Cu" "In13.Cu" "In14.Cu"
			"In15.Cu" "In16.Cu"
		)
		(hatch none 0.5)
		(connect_pads
			(clearance 0)
		)
		(min_thickness 0.25)
		(keepout
			(tracks not_allowed)
			(vias allowed)
			(pads allowed)
			(copperpour not_allowed)
			(footprints allowed)
		)
		(placement
			(enabled no)
			(sheetname "")
		)
		(fill
			(thermal_gap 0.5)
			(thermal_bridge_width 0.5)
			(island_removal_mode 0)
		)
		(polygon
			(pts
				(arc
					(start 374.018556 -186.052968)
					(mid 374.377766 -185.904178)
					(end 374.526556 -185.544968)
				)
				(arc
					(start 374.526556 -185.544968)
					(mid 374.458499 -185.290971)
					(end 374.272556 -185.10504)
				)
				(arc
					(start 373.348504 -184.571386)
					(mid 373.22621 -184.520849)
					(end 373.095012 -184.503568)
				)
				(arc
					(start 373.094504 -184.503568)
					(mid 372.735294 -184.652358)
					(end 372.586504 -185.011568)
				)
				(arc
					(start 372.586504 -185.011568)
					(mid 372.654561 -185.265565)
					(end 372.840504 -185.451496)
				)
				(arc
					(start 373.764556 -185.98515)
					(mid 373.88685 -186.035687)
					(end 374.018048 -186.052968)
				)
			)
		)
	)
	(zone
		(layers "F.Cu" "B.Cu" "In1.Cu" "In2.Cu" "In3.Cu" "In4.Cu" "In5.Cu" "In6.Cu"
			"In7.Cu" "In8.Cu" "In9.Cu" "In10.Cu" "In11.Cu" "In12.Cu" "In13.Cu" "In14.Cu"
			"In15.Cu" "In16.Cu"
		)
		(hatch none 0.5)
		(connect_pads
			(clearance 0)
		)
		(min_thickness 0.25)
		(keepout
			(tracks not_allowed)
			(vias allowed)
			(pads allowed)
			(copperpour not_allowed)
			(footprints allowed)
		)
		(placement
			(enabled no)
			(sheetname "")
		)
		(fill
			(thermal_gap 0.5)
			(thermal_bridge_width 0.5)
			(island_removal_mode 0)
		)
		(polygon
			(pts
				(arc
					(start 375.525792 -285.661354)
					(mid 374.867932 -285.661354)
					(end 375.525792 -285.661354)
				)
			)
		)
	)
	(zone
		(layers "F.Cu" "B.Cu" "In1.Cu" "In2.Cu" "In3.Cu" "In4.Cu" "In5.Cu" "In6.Cu"
			"In7.Cu" "In8.Cu" "In9.Cu" "In10.Cu" "In11.Cu" "In12.Cu" "In13.Cu" "In14.Cu"
			"In15.Cu" "In16.Cu"
		)
		(hatch none 0.5)
		(connect_pads
			(clearance 0)
		)
		(min_thickness 0.25)
		(keepout
			(tracks not_allowed)
			(vias allowed)
			(pads allowed)
			(copperpour not_allowed)
			(footprints allowed)
		)
		(placement
			(enabled no)
			(sheetname "")
		)
		(fill
			(thermal_gap 0.5)
			(thermal_bridge_width 0.5)
			(island_removal_mode 0)
		)
		(polygon
			(pts
				(arc
					(start 357.37038 -34.859468)
					(mid 356.98938 -35.240468)
					(end 357.37038 -35.621468)
				)
				(arc
					(start 358.23398 -35.621468)
					(mid 358.61498 -35.240468)
					(end 358.23398 -34.859468)
				)
			)
		)
	)
	(zone
		(layers "F.Cu" "B.Cu" "In1.Cu" "In2.Cu" "In3.Cu" "In4.Cu" "In5.Cu" "In6.Cu"
			"In7.Cu" "In8.Cu" "In9.Cu" "In10.Cu" "In11.Cu" "In12.Cu" "In13.Cu" "In14.Cu"
			"In15.Cu" "In16.Cu"
		)
		(hatch none 0.5)
		(connect_pads
			(clearance 0)
		)
		(min_thickness 0.25)
		(keepout
			(tracks not_allowed)
			(vias allowed)
			(pads allowed)
			(copperpour not_allowed)
			(footprints allowed)
		)
		(placement
			(enabled no)
			(sheetname "")
		)
		(fill
			(thermal_gap 0.5)
			(thermal_bridge_width 0.5)
			(island_removal_mode 0)
		)
		(polygon
			(pts
				(arc
					(start 347.22181 -218.692222)
					(mid 346.56395 -218.692222)
					(end 347.22181 -218.692222)
				)
			)
		)
	)
	(zone
		(layers "F.Cu" "B.Cu" "In1.Cu" "In2.Cu" "In3.Cu" "In4.Cu" "In5.Cu" "In6.Cu"
			"In7.Cu" "In8.Cu" "In9.Cu" "In10.Cu" "In11.Cu" "In12.Cu" "In13.Cu" "In14.Cu"
			"In15.Cu" "In16.Cu"
		)
		(hatch none 0.5)
		(connect_pads
			(clearance 0)
		)
		(min_thickness 0.25)
		(keepout
			(tracks not_allowed)
			(vias allowed)
			(pads allowed)
			(copperpour not_allowed)
			(footprints allowed)
		)
		(placement
			(enabled no)
			(sheetname "")
		)
		(fill
			(thermal_gap 0.5)
			(thermal_bridge_width 0.5)
			(island_removal_mode 0)
		)
		(polygon
			(pts
				(arc
					(start 119.299482 -215.436704)
					(mid 119.957342 -215.436704)
					(end 119.299482 -215.436704)
				)
			)
		)
	)
	(zone
		(layers "F.Cu" "B.Cu" "In1.Cu" "In2.Cu" "In3.Cu" "In4.Cu" "In5.Cu" "In6.Cu"
			"In7.Cu" "In8.Cu" "In9.Cu" "In10.Cu" "In11.Cu" "In12.Cu" "In13.Cu" "In14.Cu"
			"In15.Cu" "In16.Cu"
		)
		(hatch none 0.5)
		(connect_pads
			(clearance 0)
		)
		(min_thickness 0.25)
		(keepout
			(tracks not_allowed)
			(vias allowed)
			(pads allowed)
			(copperpour not_allowed)
			(footprints allowed)
		)
		(placement
			(enabled no)
			(sheetname "")
		)
		(fill
			(thermal_gap 0.5)
			(thermal_bridge_width 0.5)
			(island_removal_mode 0)
		)
		(polygon
			(pts
				(arc
					(start 135.276082 -215.436704)
					(mid 135.933942 -215.436704)
					(end 135.276082 -215.436704)
				)
			)
		)
	)
	(zone
		(layers "F.Cu" "B.Cu" "In1.Cu" "In2.Cu" "In3.Cu" "In4.Cu" "In5.Cu" "In6.Cu"
			"In7.Cu" "In8.Cu" "In9.Cu" "In10.Cu" "In11.Cu" "In12.Cu" "In13.Cu" "In14.Cu"
			"In15.Cu" "In16.Cu"
		)
		(hatch none 0.5)
		(connect_pads
			(clearance 0)
		)
		(min_thickness 0.25)
		(keepout
			(tracks not_allowed)
			(vias allowed)
			(pads allowed)
			(copperpour not_allowed)
			(footprints allowed)
		)
		(placement
			(enabled no)
			(sheetname "")
		)
		(fill
			(thermal_gap 0.5)
			(thermal_bridge_width 0.5)
			(island_removal_mode 0)
		)
		(polygon
			(pts
				(arc
					(start 369.77701 -218.692222)
					(mid 369.11915 -218.692222)
					(end 369.77701 -218.692222)
				)
			)
		)
	)
	(zone
		(layers "F.Cu" "B.Cu" "In1.Cu" "In2.Cu" "In3.Cu" "In4.Cu" "In5.Cu" "In6.Cu"
			"In7.Cu" "In8.Cu" "In9.Cu" "In10.Cu" "In11.Cu" "In12.Cu" "In13.Cu" "In14.Cu"
			"In15.Cu" "In16.Cu"
		)
		(hatch none 0.5)
		(connect_pads
			(clearance 0)
		)
		(min_thickness 0.25)
		(keepout
			(tracks not_allowed)
			(vias allowed)
			(pads allowed)
			(copperpour not_allowed)
			(footprints allowed)
		)
		(placement
			(enabled no)
			(sheetname "")
		)
		(fill
			(thermal_gap 0.5)
			(thermal_bridge_width 0.5)
			(island_removal_mode 0)
		)
		(polygon
			(pts
				(arc
					(start 107.192064 -275.8948)
					(mid 107.849924 -275.8948)
					(end 107.192064 -275.8948)
				)
			)
		)
	)
	(zone
		(layers "F.Cu" "B.Cu" "In1.Cu" "In2.Cu" "In3.Cu" "In4.Cu" "In5.Cu" "In6.Cu"
			"In7.Cu" "In8.Cu" "In9.Cu" "In10.Cu" "In11.Cu" "In12.Cu" "In13.Cu" "In14.Cu"
			"In15.Cu" "In16.Cu"
		)
		(hatch none 0.5)
		(connect_pads
			(clearance 0)
		)
		(min_thickness 0.25)
		(keepout
			(tracks not_allowed)
			(vias allowed)
			(pads allowed)
			(copperpour not_allowed)
			(footprints allowed)
		)
		(placement
			(enabled no)
			(sheetname "")
		)
		(fill
			(thermal_gap 0.5)
			(thermal_bridge_width 0.5)
			(island_removal_mode 0)
		)
		(polygon
			(pts
				(arc
					(start 261.856982 5.031994)
					(mid 262.237982 4.650994)
					(end 262.618982 5.031994)
				)
				(arc
					(start 262.618982 5.895594)
					(mid 262.237982 6.276594)
					(end 261.856982 5.895594)
				)
			)
		)
	)
	(zone
		(layers "F.Cu" "B.Cu" "In1.Cu" "In2.Cu" "In3.Cu" "In4.Cu" "In5.Cu" "In6.Cu"
			"In7.Cu" "In8.Cu" "In9.Cu" "In10.Cu" "In11.Cu" "In12.Cu" "In13.Cu" "In14.Cu"
			"In15.Cu" "In16.Cu"
		)
		(hatch none 0.5)
		(connect_pads
			(clearance 0)
		)
		(min_thickness 0.25)
		(keepout
			(tracks not_allowed)
			(vias allowed)
			(pads allowed)
			(copperpour not_allowed)
			(footprints allowed)
		)
		(placement
			(enabled no)
			(sheetname "")
		)
		(fill
			(thermal_gap 0.5)
			(thermal_bridge_width 0.5)
			(island_removal_mode 0)
		)
		(polygon
			(pts
				(arc
					(start 352.871024 -49.826672)
					(mid 352.490024 -50.207672)
					(end 352.871024 -50.588672)
				)
				(arc
					(start 353.734624 -50.588672)
					(mid 354.115624 -50.207672)
					(end 353.734624 -49.826672)
				)
			)
		)
	)
	(zone
		(layers "F.Cu" "B.Cu" "In1.Cu" "In2.Cu" "In3.Cu" "In4.Cu" "In5.Cu" "In6.Cu"
			"In7.Cu" "In8.Cu" "In9.Cu" "In10.Cu" "In11.Cu" "In12.Cu" "In13.Cu" "In14.Cu"
			"In15.Cu" "In16.Cu"
		)
		(hatch none 0.5)
		(connect_pads
			(clearance 0)
		)
		(min_thickness 0.25)
		(keepout
			(tracks not_allowed)
			(vias allowed)
			(pads allowed)
			(copperpour not_allowed)
			(footprints allowed)
		)
		(placement
			(enabled no)
			(sheetname "")
		)
		(fill
			(thermal_gap 0.5)
			(thermal_bridge_width 0.5)
			(island_removal_mode 0)
		)
		(polygon
			(pts
				(arc
					(start 88.286082 -215.436704)
					(mid 88.943942 -215.436704)
					(end 88.286082 -215.436704)
				)
			)
		)
	)
	(zone
		(layers "F.Cu" "B.Cu" "In1.Cu" "In2.Cu" "In3.Cu" "In4.Cu" "In5.Cu" "In6.Cu"
			"In7.Cu" "In8.Cu" "In9.Cu" "In10.Cu" "In11.Cu" "In12.Cu" "In13.Cu" "In14.Cu"
			"In15.Cu" "In16.Cu"
		)
		(hatch none 0.5)
		(connect_pads
			(clearance 0)
		)
		(min_thickness 0.25)
		(keepout
			(tracks not_allowed)
			(vias allowed)
			(pads allowed)
			(copperpour not_allowed)
			(footprints allowed)
		)
		(placement
			(enabled no)
			(sheetname "")
		)
		(fill
			(thermal_gap 0.5)
			(thermal_bridge_width 0.5)
			(island_removal_mode 0)
		)
		(polygon
			(pts
				(arc
					(start 389.80237 -400.477228)
					(mid 389.42137 -400.858228)
					(end 389.80237 -401.239228)
				)
				(arc
					(start 390.66597 -401.239228)
					(mid 391.04697 -400.858228)
					(end 390.66597 -400.477228)
				)
			)
		)
	)
	(zone
		(layers "F.Cu" "B.Cu" "In1.Cu" "In2.Cu" "In3.Cu" "In4.Cu" "In5.Cu" "In6.Cu"
			"In7.Cu" "In8.Cu" "In9.Cu" "In10.Cu" "In11.Cu" "In12.Cu" "In13.Cu" "In14.Cu"
			"In15.Cu" "In16.Cu"
		)
		(hatch none 0.5)
		(connect_pads
			(clearance 0)
		)
		(min_thickness 0.25)
		(keepout
			(tracks not_allowed)
			(vias allowed)
			(pads allowed)
			(copperpour not_allowed)
			(footprints allowed)
		)
		(placement
			(enabled no)
			(sheetname "")
		)
		(fill
			(thermal_gap 0.5)
			(thermal_bridge_width 0.5)
			(island_removal_mode 0)
		)
		(polygon
			(pts
				(arc
					(start 90.823542 -217.064336)
					(mid 90.165682 -217.064336)
					(end 90.823542 -217.064336)
				)
			)
		)
	)
	(zone
		(layers "F.Cu" "B.Cu" "In1.Cu" "In2.Cu" "In3.Cu" "In4.Cu" "In5.Cu" "In6.Cu"
			"In7.Cu" "In8.Cu" "In9.Cu" "In10.Cu" "In11.Cu" "In12.Cu" "In13.Cu" "In14.Cu"
			"In15.Cu" "In16.Cu"
		)
		(hatch none 0.5)
		(connect_pads
			(clearance 0)
		)
		(min_thickness 0.25)
		(keepout
			(tracks not_allowed)
			(vias allowed)
			(pads allowed)
			(copperpour not_allowed)
			(footprints allowed)
		)
		(placement
			(enabled no)
			(sheetname "")
		)
		(fill
			(thermal_gap 0.5)
			(thermal_bridge_width 0.5)
			(island_removal_mode 0)
		)
		(polygon
			(pts
				(arc
					(start 158.260034 -409.649168)
					(mid 157.879034 -410.030168)
					(end 158.260034 -410.411168)
				)
				(arc
					(start 159.123634 -410.411168)
					(mid 159.504634 -410.030168)
					(end 159.123634 -409.649168)
				)
			)
		)
	)
	(zone
		(layers "F.Cu" "B.Cu" "In1.Cu" "In2.Cu" "In3.Cu" "In4.Cu" "In5.Cu" "In6.Cu"
			"In7.Cu" "In8.Cu" "In9.Cu" "In10.Cu" "In11.Cu" "In12.Cu" "In13.Cu" "In14.Cu"
			"In15.Cu" "In16.Cu"
		)
		(hatch none 0.5)
		(connect_pads
			(clearance 0)
		)
		(min_thickness 0.25)
		(keepout
			(tracks not_allowed)
			(vias allowed)
			(pads allowed)
			(copperpour not_allowed)
			(footprints allowed)
		)
		(placement
			(enabled no)
			(sheetname "")
		)
		(fill
			(thermal_gap 0.5)
			(thermal_bridge_width 0.5)
			(island_removal_mode 0)
		)
		(polygon
			(pts
				(arc
					(start 356.10165 -274.982432)
					(mid 356.029661 -274.910273)
					(end 355.931216 -274.88388)
				)
				(arc
					(start 355.931216 -274.88388)
					(mid 355.792022 -274.941536)
					(end 355.734366 -275.08073)
				)
				(arc
					(start 355.734366 -275.08073)
					(mid 355.741123 -275.131611)
					(end 355.760782 -275.179028)
				)
				(arc
					(start 356.230682 -275.993098)
					(mid 356.302671 -276.065257)
					(end 356.401116 -276.09165)
				)
				(arc
					(start 356.401116 -276.09165)
					(mid 356.54031 -276.033994)
					(end 356.597966 -275.8948)
				)
				(arc
					(start 356.597966 -275.8948)
					(mid 356.591209 -275.843919)
					(end 356.57155 -275.796502)
				)
			)
		)
	)
	(zone
		(layers "F.Cu" "B.Cu" "In1.Cu" "In2.Cu" "In3.Cu" "In4.Cu" "In5.Cu" "In6.Cu"
			"In7.Cu" "In8.Cu" "In9.Cu" "In10.Cu" "In11.Cu" "In12.Cu" "In13.Cu" "In14.Cu"
			"In15.Cu" "In16.Cu"
		)
		(hatch none 0.5)
		(connect_pads
			(clearance 0)
		)
		(min_thickness 0.25)
		(keepout
			(tracks not_allowed)
			(vias allowed)
			(pads allowed)
			(copperpour not_allowed)
			(footprints allowed)
		)
		(placement
			(enabled no)
			(sheetname "")
		)
		(fill
			(thermal_gap 0.5)
			(thermal_bridge_width 0.5)
			(island_removal_mode 0)
		)
		(polygon
			(pts
				(arc
					(start 406.805384 -17.220438)
					(mid 406.424384 -17.601438)
					(end 406.805384 -17.982438)
				)
				(arc
					(start 407.668984 -17.982438)
					(mid 408.049984 -17.601438)
					(end 407.668984 -17.220438)
				)
			)
		)
	)
	(zone
		(layers "F.Cu" "B.Cu" "In1.Cu" "In2.Cu" "In3.Cu" "In4.Cu" "In5.Cu" "In6.Cu"
			"In7.Cu" "In8.Cu" "In9.Cu" "In10.Cu" "In11.Cu" "In12.Cu" "In13.Cu" "In14.Cu"
			"In15.Cu" "In16.Cu"
		)
		(hatch none 0.5)
		(connect_pads
			(clearance 0)
		)
		(min_thickness 0.25)
		(keepout
			(tracks not_allowed)
			(vias allowed)
			(pads allowed)
			(copperpour not_allowed)
			(footprints allowed)
		)
		(placement
			(enabled no)
			(sheetname "")
		)
		(fill
			(thermal_gap 0.5)
			(thermal_bridge_width 0.5)
			(island_removal_mode 0)
		)
		(polygon
			(pts
				(arc
					(start 377.405646 -288.917126)
					(mid 376.747786 -288.917126)
					(end 377.405646 -288.917126)
				)
			)
		)
	)
	(zone
		(layers "F.Cu" "B.Cu" "In1.Cu" "In2.Cu" "In3.Cu" "In4.Cu" "In5.Cu" "In6.Cu"
			"In7.Cu" "In8.Cu" "In9.Cu" "In10.Cu" "In11.Cu" "In12.Cu" "In13.Cu" "In14.Cu"
			"In15.Cu" "In16.Cu"
		)
		(hatch none 0.5)
		(connect_pads
			(clearance 0)
		)
		(min_thickness 0.25)
		(keepout
			(tracks not_allowed)
			(vias allowed)
			(pads allowed)
			(copperpour not_allowed)
			(footprints allowed)
		)
		(placement
			(enabled no)
			(sheetname "")
		)
		(fill
			(thermal_gap 0.5)
			(thermal_bridge_width 0.5)
			(island_removal_mode 0)
		)
		(polygon
			(pts
				(arc
					(start 370.827046 -288.917126)
					(mid 370.169186 -288.917126)
					(end 370.827046 -288.917126)
				)
			)
		)
	)
	(zone
		(layers "F.Cu" "B.Cu" "In1.Cu" "In2.Cu" "In3.Cu" "In4.Cu" "In5.Cu" "In6.Cu"
			"In7.Cu" "In8.Cu" "In9.Cu" "In10.Cu" "In11.Cu" "In12.Cu" "In13.Cu" "In14.Cu"
			"In15.Cu" "In16.Cu"
		)
		(hatch none 0.5)
		(connect_pads
			(clearance 0)
		)
		(min_thickness 0.25)
		(keepout
			(tracks not_allowed)
			(vias allowed)
			(pads allowed)
			(copperpour not_allowed)
			(footprints allowed)
		)
		(placement
			(enabled no)
			(sheetname "")
		)
		(fill
			(thermal_gap 0.5)
			(thermal_bridge_width 0.5)
			(island_removal_mode 0)
		)
		(polygon
			(pts
				(arc
					(start 72.195182 -7.105396)
					(mid 72.576182 -6.724396)
					(end 72.195182 -6.343396)
				)
				(arc
					(start 71.331582 -6.343396)
					(mid 70.950582 -6.724396)
					(end 71.331582 -7.105396)
				)
			)
		)
	)
	(zone
		(layers "F.Cu" "B.Cu" "In1.Cu" "In2.Cu" "In3.Cu" "In4.Cu" "In5.Cu" "In6.Cu"
			"In7.Cu" "In8.Cu" "In9.Cu" "In10.Cu" "In11.Cu" "In12.Cu" "In13.Cu" "In14.Cu"
			"In15.Cu" "In16.Cu"
		)
		(hatch none 0.5)
		(connect_pads
			(clearance 0)
		)
		(min_thickness 0.25)
		(keepout
			(tracks not_allowed)
			(vias allowed)
			(pads allowed)
			(copperpour not_allowed)
			(footprints allowed)
		)
		(placement
			(enabled no)
			(sheetname "")
		)
		(fill
			(thermal_gap 0.5)
			(thermal_bridge_width 0.5)
			(island_removal_mode 0)
		)
		(polygon
			(pts
				(arc
					(start 358.49941 -215.436704)
					(mid 357.84155 -215.436704)
					(end 358.49941 -215.436704)
				)
			)
		)
	)
	(zone
		(layers "F.Cu" "B.Cu" "In1.Cu" "In2.Cu" "In3.Cu" "In4.Cu" "In5.Cu" "In6.Cu"
			"In7.Cu" "In8.Cu" "In9.Cu" "In10.Cu" "In11.Cu" "In12.Cu" "In13.Cu" "In14.Cu"
			"In15.Cu" "In16.Cu"
		)
		(hatch none 0.5)
		(connect_pads
			(clearance 0)
		)
		(min_thickness 0.25)
		(keepout
			(tracks not_allowed)
			(vias allowed)
			(pads allowed)
			(copperpour not_allowed)
			(footprints allowed)
		)
		(placement
			(enabled no)
			(sheetname "")
		)
		(fill
			(thermal_gap 0.5)
			(thermal_bridge_width 0.5)
			(island_removal_mode 0)
		)
		(polygon
			(pts
				(arc
					(start 127.867918 -288.917126)
					(mid 128.525778 -288.917126)
					(end 127.867918 -288.917126)
				)
			)
		)
	)
	(zone
		(layers "F.Cu" "B.Cu" "In1.Cu" "In2.Cu" "In3.Cu" "In4.Cu" "In5.Cu" "In6.Cu"
			"In7.Cu" "In8.Cu" "In9.Cu" "In10.Cu" "In11.Cu" "In12.Cu" "In13.Cu" "In14.Cu"
			"In15.Cu" "In16.Cu"
		)
		(hatch none 0.5)
		(connect_pads
			(clearance 0)
		)
		(min_thickness 0.25)
		(keepout
			(tracks not_allowed)
			(vias allowed)
			(pads allowed)
			(copperpour not_allowed)
			(footprints allowed)
		)
		(placement
			(enabled no)
			(sheetname "")
		)
		(fill
			(thermal_gap 0.5)
			(thermal_bridge_width 0.5)
			(island_removal_mode 0)
		)
		(polygon
			(pts
				(arc
					(start 111.8108 -224.291144)
					(mid 111.738811 -224.218985)
					(end 111.640366 -224.192592)
				)
				(arc
					(start 111.640366 -224.192592)
					(mid 111.501172 -224.250248)
					(end 111.443516 -224.389442)
				)
				(arc
					(start 111.443516 -224.389442)
					(mid 111.450273 -224.440323)
					(end 111.469932 -224.48774)
				)
				(arc
					(start 111.939578 -225.301556)
					(mid 112.011567 -225.373715)
					(end 112.110012 -225.400108)
				)
				(arc
					(start 112.110012 -225.400108)
					(mid 112.249206 -225.342452)
					(end 112.306862 -225.203258)
				)
				(arc
					(start 112.306862 -225.203258)
					(mid 112.300105 -225.152377)
					(end 112.280446 -225.10496)
				)
			)
		)
	)
	(zone
		(layers "F.Cu" "B.Cu" "In1.Cu" "In2.Cu" "In3.Cu" "In4.Cu" "In5.Cu" "In6.Cu"
			"In7.Cu" "In8.Cu" "In9.Cu" "In10.Cu" "In11.Cu" "In12.Cu" "In13.Cu" "In14.Cu"
			"In15.Cu" "In16.Cu"
		)
		(hatch none 0.5)
		(connect_pads
			(clearance 0)
		)
		(min_thickness 0.25)
		(keepout
			(tracks not_allowed)
			(vias allowed)
			(pads allowed)
			(copperpour not_allowed)
			(footprints allowed)
		)
		(placement
			(enabled no)
			(sheetname "")
		)
		(fill
			(thermal_gap 0.5)
			(thermal_bridge_width 0.5)
			(island_removal_mode 0)
		)
		(polygon
			(pts
				(arc
					(start 295.11244 -162.715448)
					(mid 294.73144 -163.096448)
					(end 295.11244 -163.477448)
				)
				(arc
					(start 295.97604 -163.477448)
					(mid 296.35704 -163.096448)
					(end 295.97604 -162.715448)
				)
			)
		)
	)
	(zone
		(layers "F.Cu" "B.Cu" "In1.Cu" "In2.Cu" "In3.Cu" "In4.Cu" "In5.Cu" "In6.Cu"
			"In7.Cu" "In8.Cu" "In9.Cu" "In10.Cu" "In11.Cu" "In12.Cu" "In13.Cu" "In14.Cu"
			"In15.Cu" "In16.Cu"
		)
		(hatch none 0.5)
		(connect_pads
			(clearance 0)
		)
		(min_thickness 0.25)
		(keepout
			(tracks allowed)
			(vias allowed)
			(pads allowed)
			(copperpour allowed)
			(footprints not_allowed)
		)
		(placement
			(enabled no)
			(sheetname "")
		)
		(fill
			(thermal_gap 0.5)
			(thermal_bridge_width 0.5)
			(island_removal_mode 0)
		)
		(polygon
			(pts
				(arc
					(start 13.718032 -32.098488)
					(mid 17.344957 -31.977775)
					(end 17.224248 -28.350718)
				)
				(arc
					(start 16.055848 -27.257756)
					(mid 12.428787 -27.378597)
					(end 12.549632 -31.005526)
				)
			)
		)
	)
	(zone
		(layers "F.Cu" "B.Cu" "In1.Cu" "In2.Cu" "In3.Cu" "In4.Cu" "In5.Cu" "In6.Cu"
			"In7.Cu" "In8.Cu" "In9.Cu" "In10.Cu" "In11.Cu" "In12.Cu" "In13.Cu" "In14.Cu"
			"In15.Cu" "In16.Cu"
		)
		(hatch none 0.5)
		(connect_pads
			(clearance 0)
		)
		(min_thickness 0.25)
		(keepout
			(tracks not_allowed)
			(vias allowed)
			(pads allowed)
			(copperpour not_allowed)
			(footprints allowed)
		)
		(placement
			(enabled no)
			(sheetname "")
		)
		(fill
			(thermal_gap 0.5)
			(thermal_bridge_width 0.5)
			(island_removal_mode 0)
		)
		(polygon
			(pts
				(arc
					(start 132.174742 -217.064336)
					(mid 131.516882 -217.064336)
					(end 132.174742 -217.064336)
				)
			)
		)
	)
	(zone
		(layers "F.Cu" "B.Cu" "In1.Cu" "In2.Cu" "In3.Cu" "In4.Cu" "In5.Cu" "In6.Cu"
			"In7.Cu" "In8.Cu" "In9.Cu" "In10.Cu" "In11.Cu" "In12.Cu" "In13.Cu" "In14.Cu"
			"In15.Cu" "In16.Cu"
		)
		(hatch none 0.5)
		(connect_pads
			(clearance 0)
		)
		(min_thickness 0.25)
		(keepout
			(tracks not_allowed)
			(vias allowed)
			(pads allowed)
			(copperpour not_allowed)
			(footprints allowed)
		)
		(placement
			(enabled no)
			(sheetname "")
		)
		(fill
			(thermal_gap 0.5)
			(thermal_bridge_width 0.5)
			(island_removal_mode 0)
		)
		(polygon
			(pts
				(arc
					(start 107.111292 -221.231968)
					(mid 107.130976 -221.184558)
					(end 107.137708 -221.13367)
				)
				(arc
					(start 107.137708 -221.13367)
					(mid 107.080052 -220.994476)
					(end 106.940858 -220.93682)
				)
				(arc
					(start 106.940858 -220.93682)
					(mid 106.842427 -220.963236)
					(end 106.770424 -221.035372)
				)
				(arc
					(start 106.300778 -221.849442)
					(mid 106.281094 -221.896852)
					(end 106.274362 -221.94774)
				)
				(arc
					(start 106.274362 -221.94774)
					(mid 106.332018 -222.086934)
					(end 106.471212 -222.14459)
				)
				(arc
					(start 106.471212 -222.14459)
					(mid 106.569643 -222.118174)
					(end 106.641646 -222.046038)
				)
			)
		)
	)
	(zone
		(layers "F.Cu" "B.Cu" "In1.Cu" "In2.Cu" "In3.Cu" "In4.Cu" "In5.Cu" "In6.Cu"
			"In7.Cu" "In8.Cu" "In9.Cu" "In10.Cu" "In11.Cu" "In12.Cu" "In13.Cu" "In14.Cu"
			"In15.Cu" "In16.Cu"
		)
		(hatch none 0.5)
		(connect_pads
			(clearance 0)
		)
		(min_thickness 0.25)
		(keepout
			(tracks not_allowed)
			(vias allowed)
			(pads allowed)
			(copperpour not_allowed)
			(footprints allowed)
		)
		(placement
			(enabled no)
			(sheetname "")
		)
		(fill
			(thermal_gap 0.5)
			(thermal_bridge_width 0.5)
			(island_removal_mode 0)
		)
		(polygon
			(pts
				(arc
					(start 94.8944 -221.035626)
					(mid 94.822411 -220.963467)
					(end 94.723966 -220.937074)
				)
				(arc
					(start 94.723966 -220.937074)
					(mid 94.584772 -220.99473)
					(end 94.527116 -221.133924)
				)
				(arc
					(start 94.527116 -221.133924)
					(mid 94.533873 -221.184805)
					(end 94.553532 -221.232222)
				)
				(arc
					(start 95.023178 -222.046038)
					(mid 95.095167 -222.118197)
					(end 95.193612 -222.14459)
				)
				(arc
					(start 95.193612 -222.14459)
					(mid 95.332806 -222.086934)
					(end 95.390462 -221.94774)
				)
				(arc
					(start 95.390462 -221.94774)
					(mid 95.383705 -221.896859)
					(end 95.364046 -221.849442)
				)
			)
		)
	)
	(zone
		(layers "F.Cu" "B.Cu" "In1.Cu" "In2.Cu" "In3.Cu" "In4.Cu" "In5.Cu" "In6.Cu"
			"In7.Cu" "In8.Cu" "In9.Cu" "In10.Cu" "In11.Cu" "In12.Cu" "In13.Cu" "In14.Cu"
			"In15.Cu" "In16.Cu"
		)
		(hatch none 0.5)
		(connect_pads
			(clearance 0)
		)
		(min_thickness 0.25)
		(keepout
			(tracks not_allowed)
			(vias allowed)
			(pads allowed)
			(copperpour not_allowed)
			(footprints allowed)
		)
		(placement
			(enabled no)
			(sheetname "")
		)
		(fill
			(thermal_gap 0.5)
			(thermal_bridge_width 0.5)
			(island_removal_mode 0)
		)
		(polygon
			(pts
				(arc
					(start 126.066296 -217.878406)
					(mid 125.408436 -217.878406)
					(end 126.066296 -217.878406)
				)
			)
		)
	)
	(zone
		(layers "F.Cu" "B.Cu" "In1.Cu" "In2.Cu" "In3.Cu" "In4.Cu" "In5.Cu" "In6.Cu"
			"In7.Cu" "In8.Cu" "In9.Cu" "In10.Cu" "In11.Cu" "In12.Cu" "In13.Cu" "In14.Cu"
			"In15.Cu" "In16.Cu"
		)
		(hatch none 0.5)
		(connect_pads
			(clearance 0)
		)
		(min_thickness 0.25)
		(keepout
			(tracks not_allowed)
			(vias allowed)
			(pads allowed)
			(copperpour not_allowed)
			(footprints allowed)
		)
		(placement
			(enabled no)
			(sheetname "")
		)
		(fill
			(thermal_gap 0.5)
			(thermal_bridge_width 0.5)
			(island_removal_mode 0)
		)
		(polygon
			(pts
				(arc
					(start 122.618754 -216.966292)
					(mid 122.546765 -216.894133)
					(end 122.44832 -216.86774)
				)
				(arc
					(start 122.44832 -216.86774)
					(mid 122.309126 -216.925396)
					(end 122.25147 -217.06459)
				)
				(arc
					(start 122.25147 -217.06459)
					(mid 122.258227 -217.115471)
					(end 122.277886 -217.162888)
				)
				(arc
					(start 122.747532 -217.976704)
					(mid 122.819521 -218.048863)
					(end 122.917966 -218.075256)
				)
				(arc
					(start 122.917966 -218.075256)
					(mid 123.05716 -218.0176)
					(end 123.114816 -217.878406)
				)
				(arc
					(start 123.114816 -217.878406)
					(mid 123.108059 -217.827525)
					(end 123.0884 -217.780108)
				)
			)
		)
	)
	(zone
		(layers "F.Cu" "B.Cu" "In1.Cu" "In2.Cu" "In3.Cu" "In4.Cu" "In5.Cu" "In6.Cu"
			"In7.Cu" "In8.Cu" "In9.Cu" "In10.Cu" "In11.Cu" "In12.Cu" "In13.Cu" "In14.Cu"
			"In15.Cu" "In16.Cu"
		)
		(hatch none 0.5)
		(connect_pads
			(clearance 0)
		)
		(min_thickness 0.25)
		(keepout
			(tracks not_allowed)
			(vias allowed)
			(pads allowed)
			(copperpour not_allowed)
			(footprints allowed)
		)
		(placement
			(enabled no)
			(sheetname "")
		)
		(fill
			(thermal_gap 0.5)
			(thermal_bridge_width 0.5)
			(island_removal_mode 0)
		)
		(polygon
			(pts
				(arc
					(start 126.377954 -216.966292)
					(mid 126.305965 -216.894133)
					(end 126.20752 -216.86774)
				)
				(arc
					(start 126.20752 -216.86774)
					(mid 126.068326 -216.925396)
					(end 126.01067 -217.06459)
				)
				(arc
					(start 126.01067 -217.06459)
					(mid 126.017427 -217.115471)
					(end 126.037086 -217.162888)
				)
				(arc
					(start 126.506732 -217.976704)
					(mid 126.578721 -218.048863)
					(end 126.677166 -218.075256)
				)
				(arc
					(start 126.677166 -218.075256)
					(mid 126.81636 -218.0176)
					(end 126.874016 -217.878406)
				)
				(arc
					(start 126.874016 -217.878406)
					(mid 126.867259 -217.827525)
					(end 126.8476 -217.780108)
				)
			)
		)
	)
	(zone
		(layers "F.Cu" "B.Cu" "In1.Cu" "In2.Cu" "In3.Cu" "In4.Cu" "In5.Cu" "In6.Cu"
			"In7.Cu" "In8.Cu" "In9.Cu" "In10.Cu" "In11.Cu" "In12.Cu" "In13.Cu" "In14.Cu"
			"In15.Cu" "In16.Cu"
		)
		(hatch none 0.5)
		(connect_pads
			(clearance 0)
		)
		(min_thickness 0.25)
		(keepout
			(tracks not_allowed)
			(vias allowed)
			(pads allowed)
			(copperpour not_allowed)
			(footprints allowed)
		)
		(placement
			(enabled no)
			(sheetname "")
		)
		(fill
			(thermal_gap 0.5)
			(thermal_bridge_width 0.5)
			(island_removal_mode 0)
		)
		(polygon
			(pts
				(arc
					(start 374.318022 -220.22181)
					(mid 374.246033 -220.149651)
					(end 374.147588 -220.123258)
				)
				(arc
					(start 374.147588 -220.123258)
					(mid 374.008394 -220.180914)
					(end 373.950738 -220.320108)
				)
				(arc
					(start 373.950738 -220.320108)
					(mid 373.957495 -220.370989)
					(end 373.977154 -220.418406)
				)
				(arc
					(start 374.4468 -221.232222)
					(mid 374.518789 -221.304381)
					(end 374.617234 -221.330774)
				)
				(arc
					(start 374.617234 -221.330774)
					(mid 374.756428 -221.273118)
					(end 374.814084 -221.133924)
				)
				(arc
					(start 374.814084 -221.133924)
					(mid 374.807327 -221.083043)
					(end 374.787668 -221.035626)
				)
			)
		)
	)
	(zone
		(layers "F.Cu" "B.Cu" "In1.Cu" "In2.Cu" "In3.Cu" "In4.Cu" "In5.Cu" "In6.Cu"
			"In7.Cu" "In8.Cu" "In9.Cu" "In10.Cu" "In11.Cu" "In12.Cu" "In13.Cu" "In14.Cu"
			"In15.Cu" "In16.Cu"
		)
		(hatch none 0.5)
		(connect_pads
			(clearance 0)
		)
		(min_thickness 0.25)
		(keepout
			(tracks not_allowed)
			(vias allowed)
			(pads allowed)
			(copperpour not_allowed)
			(footprints allowed)
		)
		(placement
			(enabled no)
			(sheetname "")
		)
		(fill
			(thermal_gap 0.5)
			(thermal_bridge_width 0.5)
			(island_removal_mode 0)
		)
		(polygon
			(pts
				(arc
					(start 325.422768 -400.477228)
					(mid 325.041768 -400.858228)
					(end 325.422768 -401.239228)
				)
				(arc
					(start 326.286368 -401.239228)
					(mid 326.667368 -400.858228)
					(end 326.286368 -400.477228)
				)
			)
		)
	)
	(zone
		(layers "F.Cu" "B.Cu" "In1.Cu" "In2.Cu" "In3.Cu" "In4.Cu" "In5.Cu" "In6.Cu"
			"In7.Cu" "In8.Cu" "In9.Cu" "In10.Cu" "In11.Cu" "In12.Cu" "In13.Cu" "In14.Cu"
			"In15.Cu" "In16.Cu"
		)
		(hatch none 0.5)
		(connect_pads
			(clearance 0)
		)
		(min_thickness 0.25)
		(keepout
			(tracks not_allowed)
			(vias allowed)
			(pads allowed)
			(copperpour not_allowed)
			(footprints allowed)
		)
		(placement
			(enabled no)
			(sheetname "")
		)
		(fill
			(thermal_gap 0.5)
			(thermal_bridge_width 0.5)
			(island_removal_mode 0)
		)
		(polygon
			(pts
				(arc
					(start 355.522022 -220.22181)
					(mid 355.450033 -220.149651)
					(end 355.351588 -220.123258)
				)
				(arc
					(start 355.351588 -220.123258)
					(mid 355.212394 -220.180914)
					(end 355.154738 -220.320108)
				)
				(arc
					(start 355.154738 -220.320108)
					(mid 355.161495 -220.370989)
					(end 355.181154 -220.418406)
				)
				(arc
					(start 355.6508 -221.232222)
					(mid 355.722789 -221.304381)
					(end 355.821234 -221.330774)
				)
				(arc
					(start 355.821234 -221.330774)
					(mid 355.960428 -221.273118)
					(end 356.018084 -221.133924)
				)
				(arc
					(start 356.018084 -221.133924)
					(mid 356.011327 -221.083043)
					(end 355.991668 -221.035626)
				)
			)
		)
	)
	(zone
		(layers "F.Cu" "B.Cu" "In1.Cu" "In2.Cu" "In3.Cu" "In4.Cu" "In5.Cu" "In6.Cu"
			"In7.Cu" "In8.Cu" "In9.Cu" "In10.Cu" "In11.Cu" "In12.Cu" "In13.Cu" "In14.Cu"
			"In15.Cu" "In16.Cu"
		)
		(hatch none 0.5)
		(connect_pads
			(clearance 0)
		)
		(min_thickness 0.25)
		(keepout
			(tracks not_allowed)
			(vias allowed)
			(pads allowed)
			(copperpour not_allowed)
			(footprints allowed)
		)
		(placement
			(enabled no)
			(sheetname "")
		)
		(fill
			(thermal_gap 0.5)
			(thermal_bridge_width 0.5)
			(island_removal_mode 0)
		)
		(polygon
			(pts
				(xy 639.864354 -359.975404) (xy 639.864354 -364.97514) (xy 639.559554 -364.67034) (xy 639.559554 -360.280204)
			)
		)
	)
	(zone
		(layers "F.Cu" "B.Cu" "In1.Cu" "In2.Cu" "In3.Cu" "In4.Cu" "In5.Cu" "In6.Cu"
			"In7.Cu" "In8.Cu" "In9.Cu" "In10.Cu" "In11.Cu" "In12.Cu" "In13.Cu" "In14.Cu"
			"In15.Cu" "In16.Cu"
		)
		(hatch none 0.5)
		(connect_pads
			(clearance 0)
		)
		(min_thickness 0.25)
		(keepout
			(tracks not_allowed)
			(vias allowed)
			(pads allowed)
			(copperpour not_allowed)
			(footprints allowed)
		)
		(placement
			(enabled no)
			(sheetname "")
		)
		(fill
			(thermal_gap 0.5)
			(thermal_bridge_width 0.5)
			(island_removal_mode 0)
		)
		(polygon
			(pts
				(arc
					(start 103.980742 -217.064336)
					(mid 103.322882 -217.064336)
					(end 103.980742 -217.064336)
				)
			)
		)
	)
	(zone
		(layers "F.Cu" "B.Cu" "In1.Cu" "In2.Cu" "In3.Cu" "In4.Cu" "In5.Cu" "In6.Cu"
			"In7.Cu" "In8.Cu" "In9.Cu" "In10.Cu" "In11.Cu" "In12.Cu" "In13.Cu" "In14.Cu"
			"In15.Cu" "In16.Cu"
		)
		(hatch none 0.5)
		(connect_pads
			(clearance 0)
		)
		(min_thickness 0.25)
		(keepout
			(tracks not_allowed)
			(vias allowed)
			(pads allowed)
			(copperpour not_allowed)
			(footprints allowed)
		)
		(placement
			(enabled no)
			(sheetname "")
		)
		(fill
			(thermal_gap 0.5)
			(thermal_bridge_width 0.5)
			(island_removal_mode 0)
		)
		(polygon
			(pts
				(arc
					(start 155.94838 -47.562008)
					(mid 155.56738 -47.943008)
					(end 155.94838 -48.324008)
				)
				(arc
					(start 156.81198 -48.324008)
					(mid 157.19298 -47.943008)
					(end 156.81198 -47.562008)
				)
			)
		)
	)
	(zone
		(layers "F.Cu" "B.Cu" "In1.Cu" "In2.Cu" "In3.Cu" "In4.Cu" "In5.Cu" "In6.Cu"
			"In7.Cu" "In8.Cu" "In9.Cu" "In10.Cu" "In11.Cu" "In12.Cu" "In13.Cu" "In14.Cu"
			"In15.Cu" "In16.Cu"
		)
		(hatch none 0.5)
		(connect_pads
			(clearance 0)
		)
		(min_thickness 0.25)
		(keepout
			(tracks not_allowed)
			(vias allowed)
			(pads allowed)
			(copperpour not_allowed)
			(footprints allowed)
		)
		(placement
			(enabled no)
			(sheetname "")
		)
		(fill
			(thermal_gap 0.5)
			(thermal_bridge_width 0.5)
			(island_removal_mode 0)
		)
		(polygon
			(pts
				(arc
					(start 376.197622 -216.966292)
					(mid 376.125633 -216.894133)
					(end 376.027188 -216.86774)
				)
				(arc
					(start 376.027188 -216.86774)
					(mid 375.887994 -216.925396)
					(end 375.830338 -217.06459)
				)
				(arc
					(start 375.830338 -217.06459)
					(mid 375.837095 -217.115471)
					(end 375.856754 -217.162888)
				)
				(arc
					(start 376.3264 -217.976704)
					(mid 376.398389 -218.048863)
					(end 376.496834 -218.075256)
				)
				(arc
					(start 376.496834 -218.075256)
					(mid 376.636028 -218.0176)
					(end 376.693684 -217.878406)
				)
				(arc
					(start 376.693684 -217.878406)
					(mid 376.686927 -217.827525)
					(end 376.667268 -217.780108)
				)
			)
		)
	)
	(zone
		(layers "F.Cu" "B.Cu" "In1.Cu" "In2.Cu" "In3.Cu" "In4.Cu" "In5.Cu" "In6.Cu"
			"In7.Cu" "In8.Cu" "In9.Cu" "In10.Cu" "In11.Cu" "In12.Cu" "In13.Cu" "In14.Cu"
			"In15.Cu" "In16.Cu"
		)
		(hatch none 0.5)
		(connect_pads
			(clearance 0)
		)
		(min_thickness 0.25)
		(keepout
			(tracks not_allowed)
			(vias allowed)
			(pads allowed)
			(copperpour not_allowed)
			(footprints allowed)
		)
		(placement
			(enabled no)
			(sheetname "")
		)
		(fill
			(thermal_gap 0.5)
			(thermal_bridge_width 0.5)
			(island_removal_mode 0)
		)
		(polygon
			(pts
				(arc
					(start 415.4932 -18.744438)
					(mid 415.1122 -19.125438)
					(end 415.4932 -19.506438)
				)
				(arc
					(start 416.3568 -19.506438)
					(mid 416.7378 -19.125438)
					(end 416.3568 -18.744438)
				)
			)
		)
	)
	(zone
		(layers "F.Cu" "B.Cu" "In1.Cu" "In2.Cu" "In3.Cu" "In4.Cu" "In5.Cu" "In6.Cu"
			"In7.Cu" "In8.Cu" "In9.Cu" "In10.Cu" "In11.Cu" "In12.Cu" "In13.Cu" "In14.Cu"
			"In15.Cu" "In16.Cu"
		)
		(hatch none 0.5)
		(connect_pads
			(clearance 0)
		)
		(min_thickness 0.25)
		(keepout
			(tracks not_allowed)
			(vias allowed)
			(pads allowed)
			(copperpour not_allowed)
			(footprints allowed)
		)
		(placement
			(enabled no)
			(sheetname "")
		)
		(fill
			(thermal_gap 0.5)
			(thermal_bridge_width 0.5)
			(island_removal_mode 0)
		)
		(polygon
			(pts
				(arc
					(start 128.995678 -288.103056)
					(mid 128.337818 -288.103056)
					(end 128.995678 -288.103056)
				)
			)
		)
	)
	(zone
		(layers "F.Cu" "B.Cu" "In1.Cu" "In2.Cu" "In3.Cu" "In4.Cu" "In5.Cu" "In6.Cu"
			"In7.Cu" "In8.Cu" "In9.Cu" "In10.Cu" "In11.Cu" "In12.Cu" "In13.Cu" "In14.Cu"
			"In15.Cu" "In16.Cu"
		)
		(hatch none 0.5)
		(connect_pads
			(clearance 0)
		)
		(min_thickness 0.25)
		(keepout
			(tracks not_allowed)
			(vias allowed)
			(pads allowed)
			(copperpour not_allowed)
			(footprints allowed)
		)
		(placement
			(enabled no)
			(sheetname "")
		)
		(fill
			(thermal_gap 0.5)
			(thermal_bridge_width 0.5)
			(island_removal_mode 0)
		)
		(polygon
			(pts
				(arc
					(start 349.681546 -283.219906)
					(mid 349.023686 -283.219906)
					(end 349.681546 -283.219906)
				)
			)
		)
	)
	(zone
		(layers "F.Cu" "B.Cu" "In1.Cu" "In2.Cu" "In3.Cu" "In4.Cu" "In5.Cu" "In6.Cu"
			"In7.Cu" "In8.Cu" "In9.Cu" "In10.Cu" "In11.Cu" "In12.Cu" "In13.Cu" "In14.Cu"
			"In15.Cu" "In16.Cu"
		)
		(hatch none 0.5)
		(connect_pads
			(clearance 0)
		)
		(min_thickness 0.25)
		(keepout
			(tracks not_allowed)
			(vias allowed)
			(pads allowed)
			(copperpour not_allowed)
			(footprints allowed)
		)
		(placement
			(enabled no)
			(sheetname "")
		)
		(fill
			(thermal_gap 0.5)
			(thermal_bridge_width 0.5)
			(island_removal_mode 0)
		)
		(polygon
			(pts
				(arc
					(start 115.728496 -224.389442)
					(mid 115.070636 -224.389442)
					(end 115.728496 -224.389442)
				)
			)
		)
	)
	(zone
		(layers "F.Cu" "B.Cu" "In1.Cu" "In2.Cu" "In3.Cu" "In4.Cu" "In5.Cu" "In6.Cu"
			"In7.Cu" "In8.Cu" "In9.Cu" "In10.Cu" "In11.Cu" "In12.Cu" "In13.Cu" "In14.Cu"
			"In15.Cu" "In16.Cu"
		)
		(hatch none 0.5)
		(connect_pads
			(clearance 0)
		)
		(min_thickness 0.25)
		(keepout
			(tracks not_allowed)
			(vias allowed)
			(pads allowed)
			(copperpour not_allowed)
			(footprints allowed)
		)
		(placement
			(enabled no)
			(sheetname "")
		)
		(fill
			(thermal_gap 0.5)
			(thermal_bridge_width 0.5)
			(island_removal_mode 0)
		)
		(polygon
			(pts
				(arc
					(start 342.052656 -214.622634)
					(mid 341.394796 -214.622634)
					(end 342.052656 -214.622634)
				)
			)
		)
	)
	(zone
		(layers "F.Cu" "B.Cu" "In1.Cu" "In2.Cu" "In3.Cu" "In4.Cu" "In5.Cu" "In6.Cu"
			"In7.Cu" "In8.Cu" "In9.Cu" "In10.Cu" "In11.Cu" "In12.Cu" "In13.Cu" "In14.Cu"
			"In15.Cu" "In16.Cu"
		)
		(hatch none 0.5)
		(connect_pads
			(clearance 0)
		)
		(min_thickness 0.25)
		(keepout
			(tracks not_allowed)
			(vias allowed)
			(pads allowed)
			(copperpour not_allowed)
			(footprints allowed)
		)
		(placement
			(enabled no)
			(sheetname "")
		)
		(fill
			(thermal_gap 0.5)
			(thermal_bridge_width 0.5)
			(island_removal_mode 0)
		)
		(polygon
			(pts
				(arc
					(start 99.83216 -285.563056)
					(mid 99.812476 -285.610466)
					(end 99.805744 -285.661354)
				)
				(arc
					(start 99.805744 -285.661354)
					(mid 99.8634 -285.800548)
					(end 100.002594 -285.858204)
				)
				(arc
					(start 100.002594 -285.858204)
					(mid 100.101025 -285.831788)
					(end 100.173028 -285.759652)
				)
				(arc
					(start 100.642928 -284.945582)
					(mid 100.662612 -284.898172)
					(end 100.669344 -284.847284)
				)
				(arc
					(start 100.669344 -284.847284)
					(mid 100.611688 -284.70809)
					(end 100.472494 -284.650434)
				)
				(arc
					(start 100.472494 -284.650434)
					(mid 100.374063 -284.67685)
					(end 100.30206 -284.748986)
				)
			)
		)
	)
	(zone
		(layers "F.Cu" "B.Cu" "In1.Cu" "In2.Cu" "In3.Cu" "In4.Cu" "In5.Cu" "In6.Cu"
			"In7.Cu" "In8.Cu" "In9.Cu" "In10.Cu" "In11.Cu" "In12.Cu" "In13.Cu" "In14.Cu"
			"In15.Cu" "In16.Cu"
		)
		(hatch none 0.5)
		(connect_pads
			(clearance 0)
		)
		(min_thickness 0.25)
		(keepout
			(tracks not_allowed)
			(vias allowed)
			(pads allowed)
			(copperpour not_allowed)
			(footprints allowed)
		)
		(placement
			(enabled no)
			(sheetname "")
		)
		(fill
			(thermal_gap 0.5)
			(thermal_bridge_width 0.5)
			(island_removal_mode 0)
		)
		(polygon
			(pts
				(arc
					(start 101.741478 -281.59202)
					(mid 101.083618 -281.59202)
					(end 101.741478 -281.59202)
				)
			)
		)
	)
	(zone
		(layers "F.Cu" "B.Cu" "In1.Cu" "In2.Cu" "In3.Cu" "In4.Cu" "In5.Cu" "In6.Cu"
			"In7.Cu" "In8.Cu" "In9.Cu" "In10.Cu" "In11.Cu" "In12.Cu" "In13.Cu" "In14.Cu"
			"In15.Cu" "In16.Cu"
		)
		(hatch none 0.5)
		(connect_pads
			(clearance 0)
		)
		(min_thickness 0.25)
		(keepout
			(tracks not_allowed)
			(vias allowed)
			(pads allowed)
			(copperpour not_allowed)
			(footprints allowed)
		)
		(placement
			(enabled no)
			(sheetname "")
		)
		(fill
			(thermal_gap 0.5)
			(thermal_bridge_width 0.5)
			(island_removal_mode 0)
		)
		(polygon
			(pts
				(arc
					(start 367.427764 -221.133924)
					(mid 366.769904 -221.133924)
					(end 367.427764 -221.133924)
				)
			)
		)
	)
	(zone
		(layers "F.Cu" "B.Cu" "In1.Cu" "In2.Cu" "In3.Cu" "In4.Cu" "In5.Cu" "In6.Cu"
			"In7.Cu" "In8.Cu" "In9.Cu" "In10.Cu" "In11.Cu" "In12.Cu" "In13.Cu" "In14.Cu"
			"In15.Cu" "In16.Cu"
		)
		(hatch none 0.5)
		(connect_pads
			(clearance 0)
		)
		(min_thickness 0.25)
		(keepout
			(tracks not_allowed)
			(vias allowed)
			(pads allowed)
			(copperpour not_allowed)
			(footprints allowed)
		)
		(placement
			(enabled no)
			(sheetname "")
		)
		(fill
			(thermal_gap 0.5)
			(thermal_bridge_width 0.5)
			(island_removal_mode 0)
		)
		(polygon
			(pts
				(arc
					(start 124.564394 -406.62352)
					(mid 124.183394 -407.00452)
					(end 124.564394 -407.38552)
				)
				(arc
					(start 125.427994 -407.38552)
					(mid 125.808994 -407.00452)
					(end 125.427994 -406.62352)
				)
			)
		)
	)
	(zone
		(layers "F.Cu" "B.Cu" "In1.Cu" "In2.Cu" "In3.Cu" "In4.Cu" "In5.Cu" "In6.Cu"
			"In7.Cu" "In8.Cu" "In9.Cu" "In10.Cu" "In11.Cu" "In12.Cu" "In13.Cu" "In14.Cu"
			"In15.Cu" "In16.Cu"
		)
		(hatch none 0.5)
		(connect_pads
			(clearance 0)
		)
		(min_thickness 0.25)
		(keepout
			(tracks not_allowed)
			(vias allowed)
			(pads allowed)
			(copperpour not_allowed)
			(footprints allowed)
		)
		(placement
			(enabled no)
			(sheetname "")
		)
		(fill
			(thermal_gap 0.5)
			(thermal_bridge_width 0.5)
			(island_removal_mode 0)
		)
		(polygon
			(pts
				(arc
					(start 351.451164 -217.878406)
					(mid 350.793304 -217.878406)
					(end 351.451164 -217.878406)
				)
			)
		)
	)
	(zone
		(layers "F.Cu" "B.Cu" "In1.Cu" "In2.Cu" "In3.Cu" "In4.Cu" "In5.Cu" "In6.Cu"
			"In7.Cu" "In8.Cu" "In9.Cu" "In10.Cu" "In11.Cu" "In12.Cu" "In13.Cu" "In14.Cu"
			"In15.Cu" "In16.Cu"
		)
		(hatch none 0.5)
		(connect_pads
			(clearance 0)
		)
		(min_thickness 0.25)
		(keepout
			(tracks not_allowed)
			(vias allowed)
			(pads allowed)
			(copperpour not_allowed)
			(footprints allowed)
		)
		(placement
			(enabled no)
			(sheetname "")
		)
		(fill
			(thermal_gap 0.5)
			(thermal_bridge_width 0.5)
			(island_removal_mode 0)
		)
		(polygon
			(pts
				(arc
					(start 353.330764 -217.878406)
					(mid 352.672904 -217.878406)
					(end 353.330764 -217.878406)
				)
			)
		)
	)
	(zone
		(layers "F.Cu" "B.Cu" "In1.Cu" "In2.Cu" "In3.Cu" "In4.Cu" "In5.Cu" "In6.Cu"
			"In7.Cu" "In8.Cu" "In9.Cu" "In10.Cu" "In11.Cu" "In12.Cu" "In13.Cu" "In14.Cu"
			"In15.Cu" "In16.Cu"
		)
		(hatch none 0.5)
		(connect_pads
			(clearance 0)
		)
		(min_thickness 0.25)
		(keepout
			(tracks allowed)
			(vias allowed)
			(pads allowed)
			(copperpour allowed)
			(footprints not_allowed)
		)
		(placement
			(enabled no)
			(sheetname "")
		)
		(fill
			(thermal_gap 0.5)
			(thermal_bridge_width 0.5)
			(island_removal_mode 0)
		)
		(polygon
			(pts
				(arc
					(start 467.316058 -32.29991)
					(mid 464.75015 -29.734002)
					(end 462.183988 -32.29991)
				)
				(arc
					(start 462.183988 -33.90011)
					(mid 464.75015 -36.466272)
					(end 467.316058 -33.90011)
				)
			)
		)
	)
	(zone
		(layers "F.Cu" "B.Cu" "In1.Cu" "In2.Cu" "In3.Cu" "In4.Cu" "In5.Cu" "In6.Cu"
			"In7.Cu" "In8.Cu" "In9.Cu" "In10.Cu" "In11.Cu" "In12.Cu" "In13.Cu" "In14.Cu"
			"In15.Cu" "In16.Cu"
		)
		(hatch none 0.5)
		(connect_pads
			(clearance 0)
		)
		(min_thickness 0.25)
		(keepout
			(tracks not_allowed)
			(vias allowed)
			(pads allowed)
			(copperpour not_allowed)
			(footprints allowed)
		)
		(placement
			(enabled no)
			(sheetname "")
		)
		(fill
			(thermal_gap 0.5)
			(thermal_bridge_width 0.5)
			(island_removal_mode 0)
		)
		(polygon
			(pts
				(arc
					(start 369.25885 -288.004758)
					(mid 369.186861 -287.932599)
					(end 369.088416 -287.906206)
				)
				(arc
					(start 369.088416 -287.906206)
					(mid 368.949222 -287.963862)
					(end 368.891566 -288.103056)
				)
				(arc
					(start 368.891566 -288.103056)
					(mid 368.898323 -288.153937)
					(end 368.917982 -288.201354)
				)
				(arc
					(start 369.387882 -289.015424)
					(mid 369.459871 -289.087583)
					(end 369.558316 -289.113976)
				)
				(arc
					(start 369.558316 -289.113976)
					(mid 369.69751 -289.05632)
					(end 369.755166 -288.917126)
				)
				(arc
					(start 369.755166 -288.917126)
					(mid 369.748409 -288.866245)
					(end 369.72875 -288.818828)
				)
			)
		)
	)
	(zone
		(layers "F.Cu" "B.Cu" "In1.Cu" "In2.Cu" "In3.Cu" "In4.Cu" "In5.Cu" "In6.Cu"
			"In7.Cu" "In8.Cu" "In9.Cu" "In10.Cu" "In11.Cu" "In12.Cu" "In13.Cu" "In14.Cu"
			"In15.Cu" "In16.Cu"
		)
		(hatch none 0.5)
		(connect_pads
			(clearance 0)
		)
		(min_thickness 0.25)
		(keepout
			(tracks not_allowed)
			(vias allowed)
			(pads allowed)
			(copperpour not_allowed)
			(footprints allowed)
		)
		(placement
			(enabled no)
			(sheetname "")
		)
		(fill
			(thermal_gap 0.5)
			(thermal_bridge_width 0.5)
			(island_removal_mode 0)
		)
		(polygon
			(pts
				(arc
					(start 107.739942 -217.064336)
					(mid 107.082082 -217.064336)
					(end 107.739942 -217.064336)
				)
			)
		)
	)
	(zone
		(layers "F.Cu" "B.Cu" "In1.Cu" "In2.Cu" "In3.Cu" "In4.Cu" "In5.Cu" "In6.Cu"
			"In7.Cu" "In8.Cu" "In9.Cu" "In10.Cu" "In11.Cu" "In12.Cu" "In13.Cu" "In14.Cu"
			"In15.Cu" "In16.Cu"
		)
		(hatch none 0.5)
		(connect_pads
			(clearance 0)
		)
		(min_thickness 0.25)
		(keepout
			(tracks not_allowed)
			(vias allowed)
			(pads allowed)
			(copperpour not_allowed)
			(footprints allowed)
		)
		(placement
			(enabled no)
			(sheetname "")
		)
		(fill
			(thermal_gap 0.5)
			(thermal_bridge_width 0.5)
			(island_removal_mode 0)
		)
		(polygon
			(pts
				(xy 470.499948 -145.877026) (xy 470.499948 -140.877036) (xy 470.804748 -141.181836) (xy 470.804748 -145.572226)
			)
		)
	)
	(zone
		(layers "F.Cu" "B.Cu" "In1.Cu" "In2.Cu" "In3.Cu" "In4.Cu" "In5.Cu" "In6.Cu"
			"In7.Cu" "In8.Cu" "In9.Cu" "In10.Cu" "In11.Cu" "In12.Cu" "In13.Cu" "In14.Cu"
			"In15.Cu" "In16.Cu"
		)
		(hatch none 0.5)
		(connect_pads
			(clearance 0)
		)
		(min_thickness 0.25)
		(keepout
			(tracks not_allowed)
			(vias allowed)
			(pads allowed)
			(copperpour not_allowed)
			(footprints allowed)
		)
		(placement
			(enabled no)
			(sheetname "")
		)
		(fill
			(thermal_gap 0.5)
			(thermal_bridge_width 0.5)
			(island_removal_mode 0)
		)
		(polygon
			(pts
				(arc
					(start 109.619542 -217.064336)
					(mid 108.961682 -217.064336)
					(end 109.619542 -217.064336)
				)
			)
		)
	)
	(zone
		(layers "F.Cu" "B.Cu" "In1.Cu" "In2.Cu" "In3.Cu" "In4.Cu" "In5.Cu" "In6.Cu"
			"In7.Cu" "In8.Cu" "In9.Cu" "In10.Cu" "In11.Cu" "In12.Cu" "In13.Cu" "In14.Cu"
			"In15.Cu" "In16.Cu"
		)
		(hatch none 0.5)
		(connect_pads
			(clearance 0)
		)
		(min_thickness 0.25)
		(keepout
			(tracks not_allowed)
			(vias allowed)
			(pads allowed)
			(copperpour not_allowed)
			(footprints allowed)
		)
		(placement
			(enabled no)
			(sheetname "")
		)
		(fill
			(thermal_gap 0.5)
			(thermal_bridge_width 0.5)
			(island_removal_mode 0)
		)
		(polygon
			(pts
				(arc
					(start 133.425692 -217.97645)
					(mid 133.445376 -217.92904)
					(end 133.452108 -217.878152)
				)
				(arc
					(start 133.452108 -217.878152)
					(mid 133.394452 -217.738958)
					(end 133.255258 -217.681302)
				)
				(arc
					(start 133.255258 -217.681302)
					(mid 133.156827 -217.707718)
					(end 133.084824 -217.779854)
				)
				(arc
					(start 132.615178 -218.593924)
					(mid 132.595494 -218.641334)
					(end 132.588762 -218.692222)
				)
				(arc
					(start 132.588762 -218.692222)
					(mid 132.646418 -218.831416)
					(end 132.785612 -218.889072)
				)
				(arc
					(start 132.785612 -218.889072)
					(mid 132.884043 -218.862656)
					(end 132.956046 -218.79052)
				)
			)
		)
	)
	(zone
		(layers "F.Cu" "B.Cu" "In1.Cu" "In2.Cu" "In3.Cu" "In4.Cu" "In5.Cu" "In6.Cu"
			"In7.Cu" "In8.Cu" "In9.Cu" "In10.Cu" "In11.Cu" "In12.Cu" "In13.Cu" "In14.Cu"
			"In15.Cu" "In16.Cu"
		)
		(hatch none 0.5)
		(connect_pads
			(clearance 0)
		)
		(min_thickness 0.25)
		(keepout
			(tracks not_allowed)
			(vias allowed)
			(pads allowed)
			(copperpour not_allowed)
			(footprints allowed)
		)
		(placement
			(enabled no)
			(sheetname "")
		)
		(fill
			(thermal_gap 0.5)
			(thermal_bridge_width 0.5)
			(island_removal_mode 0)
		)
		(polygon
			(pts
				(arc
					(start 376.307096 -285.759652)
					(mid 376.32678 -285.712242)
					(end 376.333512 -285.661354)
				)
				(arc
					(start 376.333512 -285.661354)
					(mid 376.275856 -285.52216)
					(end 376.136662 -285.464504)
				)
				(arc
					(start 376.136662 -285.464504)
					(mid 376.038231 -285.49092)
					(end 375.966228 -285.563056)
				)
				(arc
					(start 375.496582 -286.377126)
					(mid 375.476898 -286.424536)
					(end 375.470166 -286.475424)
				)
				(arc
					(start 375.470166 -286.475424)
					(mid 375.527822 -286.614618)
					(end 375.667016 -286.672274)
				)
				(arc
					(start 375.667016 -286.672274)
					(mid 375.765447 -286.645858)
					(end 375.83745 -286.573722)
				)
			)
		)
	)
	(zone
		(layers "F.Cu" "B.Cu" "In1.Cu" "In2.Cu" "In3.Cu" "In4.Cu" "In5.Cu" "In6.Cu"
			"In7.Cu" "In8.Cu" "In9.Cu" "In10.Cu" "In11.Cu" "In12.Cu" "In13.Cu" "In14.Cu"
			"In15.Cu" "In16.Cu"
		)
		(hatch none 0.5)
		(connect_pads
			(clearance 0)
		)
		(min_thickness 0.25)
		(keepout
			(tracks not_allowed)
			(vias allowed)
			(pads allowed)
			(copperpour not_allowed)
			(footprints allowed)
		)
		(placement
			(enabled no)
			(sheetname "")
		)
		(fill
			(thermal_gap 0.5)
			(thermal_bridge_width 0.5)
			(island_removal_mode 0)
		)
		(polygon
			(pts
				(arc
					(start 342.364314 -217.162634)
					(mid 342.383998 -217.115224)
					(end 342.39073 -217.064336)
				)
				(arc
					(start 342.39073 -217.064336)
					(mid 342.333074 -216.925142)
					(end 342.19388 -216.867486)
				)
				(arc
					(start 342.19388 -216.867486)
					(mid 342.095449 -216.893902)
					(end 342.023446 -216.966038)
				)
				(arc
					(start 341.5538 -217.780108)
					(mid 341.534116 -217.827518)
					(end 341.527384 -217.878406)
				)
				(arc
					(start 341.527384 -217.878406)
					(mid 341.58504 -218.0176)
					(end 341.724234 -218.075256)
				)
				(arc
					(start 341.724234 -218.075256)
					(mid 341.822665 -218.04884)
					(end 341.894668 -217.976704)
				)
			)
		)
	)
	(zone
		(layers "F.Cu" "B.Cu" "In1.Cu" "In2.Cu" "In3.Cu" "In4.Cu" "In5.Cu" "In6.Cu"
			"In7.Cu" "In8.Cu" "In9.Cu" "In10.Cu" "In11.Cu" "In12.Cu" "In13.Cu" "In14.Cu"
			"In15.Cu" "In16.Cu"
		)
		(hatch none 0.5)
		(connect_pads
			(clearance 0)
		)
		(min_thickness 0.25)
		(keepout
			(tracks not_allowed)
			(vias allowed)
			(pads allowed)
			(copperpour not_allowed)
			(footprints allowed)
		)
		(placement
			(enabled no)
			(sheetname "")
		)
		(fill
			(thermal_gap 0.5)
			(thermal_bridge_width 0.5)
			(island_removal_mode 0)
		)
		(polygon
			(pts
				(arc
					(start 111.969296 -221.133924)
					(mid 111.311436 -221.133924)
					(end 111.969296 -221.133924)
				)
			)
		)
	)
	(zone
		(layers "F.Cu" "B.Cu" "In1.Cu" "In2.Cu" "In3.Cu" "In4.Cu" "In5.Cu" "In6.Cu"
			"In7.Cu" "In8.Cu" "In9.Cu" "In10.Cu" "In11.Cu" "In12.Cu" "In13.Cu" "In14.Cu"
			"In15.Cu" "In16.Cu"
		)
		(hatch none 0.5)
		(connect_pads
			(clearance 0)
		)
		(min_thickness 0.25)
		(keepout
			(tracks not_allowed)
			(vias allowed)
			(pads allowed)
			(copperpour not_allowed)
			(footprints allowed)
		)
		(placement
			(enabled no)
			(sheetname "")
		)
		(fill
			(thermal_gap 0.5)
			(thermal_bridge_width 0.5)
			(island_removal_mode 0)
		)
		(polygon
			(pts
				(arc
					(start 109.101128 -273.354546)
					(mid 109.029139 -273.282387)
					(end 108.930694 -273.255994)
				)
				(arc
					(start 108.930694 -273.255994)
					(mid 108.7915 -273.31365)
					(end 108.733844 -273.452844)
				)
				(arc
					(start 108.733844 -273.452844)
					(mid 108.740601 -273.503725)
					(end 108.76026 -273.551142)
				)
				(arc
					(start 109.23016 -274.365212)
					(mid 109.302149 -274.437371)
					(end 109.400594 -274.463764)
				)
				(arc
					(start 109.400594 -274.463764)
					(mid 109.539788 -274.406108)
					(end 109.597444 -274.266914)
				)
				(arc
					(start 109.597444 -274.266914)
					(mid 109.590687 -274.216033)
					(end 109.571028 -274.168616)
				)
			)
		)
	)
	(zone
		(layers "F.Cu" "B.Cu" "In1.Cu" "In2.Cu" "In3.Cu" "In4.Cu" "In5.Cu" "In6.Cu"
			"In7.Cu" "In8.Cu" "In9.Cu" "In10.Cu" "In11.Cu" "In12.Cu" "In13.Cu" "In14.Cu"
			"In15.Cu" "In16.Cu"
		)
		(hatch none 0.5)
		(connect_pads
			(clearance 0)
		)
		(min_thickness 0.25)
		(keepout
			(tracks not_allowed)
			(vias allowed)
			(pads allowed)
			(copperpour not_allowed)
			(footprints allowed)
		)
		(placement
			(enabled no)
			(sheetname "")
		)
		(fill
			(thermal_gap 0.5)
			(thermal_bridge_width 0.5)
			(island_removal_mode 0)
		)
		(polygon
			(pts
				(arc
					(start 335.114392 -287.28924)
					(mid 334.456532 -287.28924)
					(end 335.114392 -287.28924)
				)
			)
		)
	)
	(zone
		(layers "F.Cu" "B.Cu" "In1.Cu" "In2.Cu" "In3.Cu" "In4.Cu" "In5.Cu" "In6.Cu"
			"In7.Cu" "In8.Cu" "In9.Cu" "In10.Cu" "In11.Cu" "In12.Cu" "In13.Cu" "In14.Cu"
			"In15.Cu" "In16.Cu"
		)
		(hatch none 0.5)
		(connect_pads
			(clearance 0)
		)
		(min_thickness 0.25)
		(keepout
			(tracks not_allowed)
			(vias allowed)
			(pads allowed)
			(copperpour not_allowed)
			(footprints allowed)
		)
		(placement
			(enabled no)
			(sheetname "")
		)
		(fill
			(thermal_gap 0.5)
			(thermal_bridge_width 0.5)
			(island_removal_mode 0)
		)
		(polygon
			(pts
				(arc
					(start 346.752164 -224.389442)
					(mid 346.094304 -224.389442)
					(end 346.752164 -224.389442)
				)
			)
		)
	)
	(zone
		(layers "F.Cu" "B.Cu" "In1.Cu" "In2.Cu" "In3.Cu" "In4.Cu" "In5.Cu" "In6.Cu"
			"In7.Cu" "In8.Cu" "In9.Cu" "In10.Cu" "In11.Cu" "In12.Cu" "In13.Cu" "In14.Cu"
			"In15.Cu" "In16.Cu"
		)
		(hatch none 0.5)
		(connect_pads
			(clearance 0)
		)
		(min_thickness 0.25)
		(keepout
			(tracks not_allowed)
			(vias allowed)
			(pads allowed)
			(copperpour not_allowed)
			(footprints allowed)
		)
		(placement
			(enabled no)
			(sheetname "")
		)
		(fill
			(thermal_gap 0.5)
			(thermal_bridge_width 0.5)
			(island_removal_mode 0)
		)
		(polygon
			(pts
				(arc
					(start 103.591614 -288.818828)
					(mid 103.57193 -288.866238)
					(end 103.565198 -288.917126)
				)
				(arc
					(start 103.565198 -288.917126)
					(mid 103.622854 -289.05632)
					(end 103.762048 -289.113976)
				)
				(arc
					(start 103.762048 -289.113976)
					(mid 103.860479 -289.08756)
					(end 103.932482 -289.015424)
				)
				(arc
					(start 104.402382 -288.201354)
					(mid 104.422066 -288.153944)
					(end 104.428798 -288.103056)
				)
				(arc
					(start 104.428798 -288.103056)
					(mid 104.371142 -287.963862)
					(end 104.231948 -287.906206)
				)
				(arc
					(start 104.231948 -287.906206)
					(mid 104.133517 -287.932622)
					(end 104.061514 -288.004758)
				)
			)
		)
	)
	(zone
		(layers "F.Cu" "B.Cu" "In1.Cu" "In2.Cu" "In3.Cu" "In4.Cu" "In5.Cu" "In6.Cu"
			"In7.Cu" "In8.Cu" "In9.Cu" "In10.Cu" "In11.Cu" "In12.Cu" "In13.Cu" "In14.Cu"
			"In15.Cu" "In16.Cu"
		)
		(hatch none 0.5)
		(connect_pads
			(clearance 0)
		)
		(min_thickness 0.25)
		(keepout
			(tracks not_allowed)
			(vias allowed)
			(pads allowed)
			(copperpour not_allowed)
			(footprints allowed)
		)
		(placement
			(enabled no)
			(sheetname "")
		)
		(fill
			(thermal_gap 0.5)
			(thermal_bridge_width 0.5)
			(island_removal_mode 0)
		)
		(polygon
			(pts
				(arc
					(start 344.872056 -214.622634)
					(mid 344.214196 -214.622634)
					(end 344.872056 -214.622634)
				)
			)
		)
	)
	(zone
		(layers "F.Cu" "B.Cu" "In1.Cu" "In2.Cu" "In3.Cu" "In4.Cu" "In5.Cu" "In6.Cu"
			"In7.Cu" "In8.Cu" "In9.Cu" "In10.Cu" "In11.Cu" "In12.Cu" "In13.Cu" "In14.Cu"
			"In15.Cu" "In16.Cu"
		)
		(hatch none 0.5)
		(connect_pads
			(clearance 0)
		)
		(min_thickness 0.25)
		(keepout
			(tracks not_allowed)
			(vias allowed)
			(pads allowed)
			(copperpour not_allowed)
			(footprints allowed)
		)
		(placement
			(enabled no)
			(sheetname "")
		)
		(fill
			(thermal_gap 0.5)
			(thermal_bridge_width 0.5)
			(island_removal_mode 0)
		)
		(polygon
			(pts
				(arc
					(start 146.007074 -406.62352)
					(mid 145.626074 -407.00452)
					(end 146.007074 -407.38552)
				)
				(arc
					(start 146.870674 -407.38552)
					(mid 147.251674 -407.00452)
					(end 146.870674 -406.62352)
				)
			)
		)
	)
	(zone
		(layers "F.Cu" "B.Cu" "In1.Cu" "In2.Cu" "In3.Cu" "In4.Cu" "In5.Cu" "In6.Cu"
			"In7.Cu" "In8.Cu" "In9.Cu" "In10.Cu" "In11.Cu" "In12.Cu" "In13.Cu" "In14.Cu"
			"In15.Cu" "In16.Cu"
		)
		(hatch none 0.5)
		(connect_pads
			(clearance 0)
		)
		(min_thickness 0.25)
		(keepout
			(tracks not_allowed)
			(vias allowed)
			(pads allowed)
			(copperpour not_allowed)
			(footprints allowed)
		)
		(placement
			(enabled no)
			(sheetname "")
		)
		(fill
			(thermal_gap 0.5)
			(thermal_bridge_width 0.5)
			(island_removal_mode 0)
		)
		(polygon
			(pts
				(arc
					(start 101.631496 -217.878406)
					(mid 100.973636 -217.878406)
					(end 101.631496 -217.878406)
				)
			)
		)
	)
	(zone
		(layers "F.Cu" "B.Cu" "In1.Cu" "In2.Cu" "In3.Cu" "In4.Cu" "In5.Cu" "In6.Cu"
			"In7.Cu" "In8.Cu" "In9.Cu" "In10.Cu" "In11.Cu" "In12.Cu" "In13.Cu" "In14.Cu"
			"In15.Cu" "In16.Cu"
		)
		(hatch none 0.5)
		(connect_pads
			(clearance 0)
		)
		(min_thickness 0.25)
		(keepout
			(tracks not_allowed)
			(vias allowed)
			(pads allowed)
			(copperpour not_allowed)
			(footprints allowed)
		)
		(placement
			(enabled no)
			(sheetname "")
		)
		(fill
			(thermal_gap 0.5)
			(thermal_bridge_width 0.5)
			(island_removal_mode 0)
		)
		(polygon
			(pts
				(arc
					(start 22.616668 -6.343396)
					(mid 22.235668 -6.724396)
					(end 22.616668 -7.105396)
				)
				(arc
					(start 23.480268 -7.105396)
					(mid 23.861268 -6.724396)
					(end 23.480268 -6.343396)
				)
			)
		)
	)
	(zone
		(layers "F.Cu" "B.Cu" "In1.Cu" "In2.Cu" "In3.Cu" "In4.Cu" "In5.Cu" "In6.Cu"
			"In7.Cu" "In8.Cu" "In9.Cu" "In10.Cu" "In11.Cu" "In12.Cu" "In13.Cu" "In14.Cu"
			"In15.Cu" "In16.Cu"
		)
		(hatch none 0.5)
		(connect_pads
			(clearance 0)
		)
		(min_thickness 0.25)
		(keepout
			(tracks not_allowed)
			(vias allowed)
			(pads allowed)
			(copperpour not_allowed)
			(footprints allowed)
		)
		(placement
			(enabled no)
			(sheetname "")
		)
		(fill
			(thermal_gap 0.5)
			(thermal_bridge_width 0.5)
			(island_removal_mode 0)
		)
		(polygon
			(pts
				(arc
					(start 378.705364 -221.133924)
					(mid 378.047504 -221.133924)
					(end 378.705364 -221.133924)
				)
			)
		)
	)
	(zone
		(layers "F.Cu" "B.Cu" "In1.Cu" "In2.Cu" "In3.Cu" "In4.Cu" "In5.Cu" "In6.Cu"
			"In7.Cu" "In8.Cu" "In9.Cu" "In10.Cu" "In11.Cu" "In12.Cu" "In13.Cu" "In14.Cu"
			"In15.Cu" "In16.Cu"
		)
		(hatch none 0.5)
		(connect_pads
			(clearance 0)
		)
		(min_thickness 0.25)
		(keepout
			(tracks not_allowed)
			(vias allowed)
			(pads allowed)
			(copperpour not_allowed)
			(footprints allowed)
		)
		(placement
			(enabled no)
			(sheetname "")
		)
		(fill
			(thermal_gap 0.5)
			(thermal_bridge_width 0.5)
			(island_removal_mode 0)
		)
		(polygon
			(pts
				(arc
					(start 124.656342 -223.575626)
					(mid 123.998482 -223.575626)
					(end 124.656342 -223.575626)
				)
			)
		)
	)
	(zone
		(layers "F.Cu" "B.Cu" "In1.Cu" "In2.Cu" "In3.Cu" "In4.Cu" "In5.Cu" "In6.Cu"
			"In7.Cu" "In8.Cu" "In9.Cu" "In10.Cu" "In11.Cu" "In12.Cu" "In13.Cu" "In14.Cu"
			"In15.Cu" "In16.Cu"
		)
		(hatch none 0.5)
		(connect_pads
			(clearance 0)
		)
		(min_thickness 0.25)
		(keepout
			(tracks not_allowed)
			(vias allowed)
			(pads allowed)
			(copperpour not_allowed)
			(footprints allowed)
		)
		(placement
			(enabled no)
			(sheetname "")
		)
		(fill
			(thermal_gap 0.5)
			(thermal_bridge_width 0.5)
			(island_removal_mode 0)
		)
		(polygon
			(pts
				(arc
					(start 101.553518 -288.917126)
					(mid 102.211378 -288.917126)
					(end 101.553518 -288.917126)
				)
			)
		)
	)
	(zone
		(layers "F.Cu" "B.Cu" "In1.Cu" "In2.Cu" "In3.Cu" "In4.Cu" "In5.Cu" "In6.Cu"
			"In7.Cu" "In8.Cu" "In9.Cu" "In10.Cu" "In11.Cu" "In12.Cu" "In13.Cu" "In14.Cu"
			"In15.Cu" "In16.Cu"
		)
		(hatch none 0.5)
		(connect_pads
			(clearance 0)
		)
		(min_thickness 0.25)
		(keepout
			(tracks not_allowed)
			(vias allowed)
			(pads allowed)
			(copperpour not_allowed)
			(footprints allowed)
		)
		(placement
			(enabled no)
			(sheetname "")
		)
		(fill
			(thermal_gap 0.5)
			(thermal_bridge_width 0.5)
			(island_removal_mode 0)
		)
		(polygon
			(pts
				(arc
					(start 345.28633 -288.831274)
					(mid 345.218622 -288.759423)
					(end 345.123516 -288.732976)
				)
				(arc
					(start 345.123516 -288.732976)
					(mid 344.993302 -288.786912)
					(end 344.939366 -288.917126)
				)
				(arc
					(start 344.939366 -288.917126)
					(mid 344.944817 -288.961347)
					(end 344.960702 -289.002978)
				)
				(arc
					(start 345.430348 -289.892994)
					(mid 345.498056 -289.964845)
					(end 345.593162 -289.991292)
				)
				(arc
					(start 345.593162 -289.991292)
					(mid 345.723376 -289.937356)
					(end 345.777312 -289.807142)
				)
				(arc
					(start 345.777312 -289.807142)
					(mid 345.771861 -289.762921)
					(end 345.755976 -289.72129)
				)
			)
		)
	)
	(zone
		(layers "F.Cu" "B.Cu" "In1.Cu" "In2.Cu" "In3.Cu" "In4.Cu" "In5.Cu" "In6.Cu"
			"In7.Cu" "In8.Cu" "In9.Cu" "In10.Cu" "In11.Cu" "In12.Cu" "In13.Cu" "In14.Cu"
			"In15.Cu" "In16.Cu"
		)
		(hatch none 0.5)
		(connect_pads
			(clearance 0)
		)
		(min_thickness 0.25)
		(keepout
			(tracks not_allowed)
			(vias allowed)
			(pads allowed)
			(copperpour not_allowed)
			(footprints allowed)
		)
		(placement
			(enabled no)
			(sheetname "")
		)
		(fill
			(thermal_gap 0.5)
			(thermal_bridge_width 0.5)
			(island_removal_mode 0)
		)
		(polygon
			(pts
				(arc
					(start 354.521262 -275.69795)
					(mid 354.324412 -275.8948)
					(end 354.521262 -276.09165)
				)
				(arc
					(start 355.461062 -276.09165)
					(mid 355.657912 -275.8948)
					(end 355.461062 -275.69795)
				)
			)
		)
	)
	(zone
		(layers "F.Cu" "B.Cu" "In1.Cu" "In2.Cu" "In3.Cu" "In4.Cu" "In5.Cu" "In6.Cu"
			"In7.Cu" "In8.Cu" "In9.Cu" "In10.Cu" "In11.Cu" "In12.Cu" "In13.Cu" "In14.Cu"
			"In15.Cu" "In16.Cu"
		)
		(hatch none 0.5)
		(connect_pads
			(clearance 0)
		)
		(min_thickness 0.25)
		(keepout
			(tracks allowed)
			(vias allowed)
			(pads allowed)
			(copperpour allowed)
			(footprints not_allowed)
		)
		(placement
			(enabled no)
			(sheetname "")
		)
		(fill
			(thermal_gap 0.5)
			(thermal_bridge_width 0.5)
			(island_removal_mode 0)
		)
		(polygon
			(pts
				(arc
					(start 39.046912 -74.760836)
					(mid 45.062902 -80.776826)
					(end 51.078892 -74.760836)
				)
				(arc
					(start 51.078892 -66.060828)
					(mid 45.062902 -60.044838)
					(end 39.046912 -66.060828)
				)
			)
		)
	)
	(zone
		(layers "F.Cu" "B.Cu" "In1.Cu" "In2.Cu" "In3.Cu" "In4.Cu" "In5.Cu" "In6.Cu"
			"In7.Cu" "In8.Cu" "In9.Cu" "In10.Cu" "In11.Cu" "In12.Cu" "In13.Cu" "In14.Cu"
			"In15.Cu" "In16.Cu"
		)
		(hatch none 0.5)
		(connect_pads
			(clearance 0)
		)
		(min_thickness 0.25)
		(keepout
			(tracks not_allowed)
			(vias allowed)
			(pads allowed)
			(copperpour not_allowed)
			(footprints allowed)
		)
		(placement
			(enabled no)
			(sheetname "")
		)
		(fill
			(thermal_gap 0.5)
			(thermal_bridge_width 0.5)
			(island_removal_mode 0)
		)
		(polygon
			(pts
				(arc
					(start 229.5779 -55.643272)
					(mid 229.1969 -55.262272)
					(end 228.8159 -55.643272)
				)
				(arc
					(start 228.8159 -56.506872)
					(mid 229.1969 -56.887872)
					(end 229.5779 -56.506872)
				)
			)
		)
	)
	(zone
		(layers "F.Cu" "B.Cu" "In1.Cu" "In2.Cu" "In3.Cu" "In4.Cu" "In5.Cu" "In6.Cu"
			"In7.Cu" "In8.Cu" "In9.Cu" "In10.Cu" "In11.Cu" "In12.Cu" "In13.Cu" "In14.Cu"
			"In15.Cu" "In16.Cu"
		)
		(hatch none 0.5)
		(connect_pads
			(clearance 0)
		)
		(min_thickness 0.25)
		(keepout
			(tracks not_allowed)
			(vias allowed)
			(pads allowed)
			(copperpour not_allowed)
			(footprints allowed)
		)
		(placement
			(enabled no)
			(sheetname "")
		)
		(fill
			(thermal_gap 0.5)
			(thermal_bridge_width 0.5)
			(island_removal_mode 0)
		)
		(polygon
			(pts
				(arc
					(start 105.641394 -280.581354)
					(mid 105.444544 -280.778204)
					(end 105.641394 -280.975054)
				)
				(arc
					(start 106.581194 -280.975054)
					(mid 106.778044 -280.778204)
					(end 106.581194 -280.581354)
				)
			)
		)
	)
	(zone
		(layers "F.Cu" "B.Cu" "In1.Cu" "In2.Cu" "In3.Cu" "In4.Cu" "In5.Cu" "In6.Cu"
			"In7.Cu" "In8.Cu" "In9.Cu" "In10.Cu" "In11.Cu" "In12.Cu" "In13.Cu" "In14.Cu"
			"In15.Cu" "In16.Cu"
		)
		(hatch none 0.5)
		(connect_pads
			(clearance 0)
		)
		(min_thickness 0.25)
		(keepout
			(tracks not_allowed)
			(vias allowed)
			(pads allowed)
			(copperpour not_allowed)
			(footprints allowed)
		)
		(placement
			(enabled no)
			(sheetname "")
		)
		(fill
			(thermal_gap 0.5)
			(thermal_bridge_width 0.5)
			(island_removal_mode 0)
		)
		(polygon
			(pts
				(arc
					(start 364.919514 -223.67367)
					(mid 364.939198 -223.62626)
					(end 364.94593 -223.575372)
				)
				(arc
					(start 364.94593 -223.575372)
					(mid 364.888274 -223.436178)
					(end 364.74908 -223.378522)
				)
				(arc
					(start 364.74908 -223.378522)
					(mid 364.650649 -223.404938)
					(end 364.578646 -223.477074)
				)
				(arc
					(start 364.109 -224.291144)
					(mid 364.089316 -224.338554)
					(end 364.082584 -224.389442)
				)
				(arc
					(start 364.082584 -224.389442)
					(mid 364.14024 -224.528636)
					(end 364.279434 -224.586292)
				)
				(arc
					(start 364.279434 -224.586292)
					(mid 364.377865 -224.559876)
					(end 364.449868 -224.48774)
				)
			)
		)
	)
	(zone
		(layers "F.Cu" "B.Cu" "In1.Cu" "In2.Cu" "In3.Cu" "In4.Cu" "In5.Cu" "In6.Cu"
			"In7.Cu" "In8.Cu" "In9.Cu" "In10.Cu" "In11.Cu" "In12.Cu" "In13.Cu" "In14.Cu"
			"In15.Cu" "In16.Cu"
		)
		(hatch none 0.5)
		(connect_pads
			(clearance 0)
		)
		(min_thickness 0.25)
		(keepout
			(tracks not_allowed)
			(vias allowed)
			(pads allowed)
			(copperpour not_allowed)
			(footprints allowed)
		)
		(placement
			(enabled no)
			(sheetname "")
		)
		(fill
			(thermal_gap 0.5)
			(thermal_bridge_width 0.5)
			(island_removal_mode 0)
		)
		(polygon
			(pts
				(arc
					(start 229.5779 -52.043076)
					(mid 229.1969 -51.662076)
					(end 228.8159 -52.043076)
				)
				(arc
					(start 228.8159 -52.906676)
					(mid 229.1969 -53.287676)
					(end 229.5779 -52.906676)
				)
			)
		)
	)
	(zone
		(layers "F.Cu" "B.Cu" "In1.Cu" "In2.Cu" "In3.Cu" "In4.Cu" "In5.Cu" "In6.Cu"
			"In7.Cu" "In8.Cu" "In9.Cu" "In10.Cu" "In11.Cu" "In12.Cu" "In13.Cu" "In14.Cu"
			"In15.Cu" "In16.Cu"
		)
		(hatch none 0.5)
		(connect_pads
			(clearance 0)
		)
		(min_thickness 0.25)
		(keepout
			(tracks not_allowed)
			(vias allowed)
			(pads allowed)
			(copperpour not_allowed)
			(footprints allowed)
		)
		(placement
			(enabled no)
			(sheetname "")
		)
		(fill
			(thermal_gap 0.5)
			(thermal_bridge_width 0.5)
			(island_removal_mode 0)
		)
		(polygon
			(pts
				(arc
					(start 340.173056 -214.622634)
					(mid 339.515196 -214.622634)
					(end 340.173056 -214.622634)
				)
			)
		)
	)
	(zone
		(layers "F.Cu" "B.Cu" "In1.Cu" "In2.Cu" "In3.Cu" "In4.Cu" "In5.Cu" "In6.Cu"
			"In7.Cu" "In8.Cu" "In9.Cu" "In10.Cu" "In11.Cu" "In12.Cu" "In13.Cu" "In14.Cu"
			"In15.Cu" "In16.Cu"
		)
		(hatch none 0.5)
		(connect_pads
			(clearance 0)
		)
		(min_thickness 0.25)
		(keepout
			(tracks not_allowed)
			(vias allowed)
			(pads allowed)
			(copperpour not_allowed)
			(footprints allowed)
		)
		(placement
			(enabled no)
			(sheetname "")
		)
		(fill
			(thermal_gap 0.5)
			(thermal_bridge_width 0.5)
			(island_removal_mode 0)
		)
		(polygon
			(pts
				(arc
					(start 103.432864 -279.150318)
					(mid 104.090724 -279.150318)
					(end 103.432864 -279.150318)
				)
			)
		)
	)
	(zone
		(layers "F.Cu" "B.Cu" "In1.Cu" "In2.Cu" "In3.Cu" "In4.Cu" "In5.Cu" "In6.Cu"
			"In7.Cu" "In8.Cu" "In9.Cu" "In10.Cu" "In11.Cu" "In12.Cu" "In13.Cu" "In14.Cu"
			"In15.Cu" "In16.Cu"
		)
		(hatch none 0.5)
		(connect_pads
			(clearance 0)
		)
		(min_thickness 0.25)
		(keepout
			(tracks not_allowed)
			(vias allowed)
			(pads allowed)
			(copperpour not_allowed)
			(footprints allowed)
		)
		(placement
			(enabled no)
			(sheetname "")
		)
		(fill
			(thermal_gap 0.5)
			(thermal_bridge_width 0.5)
			(island_removal_mode 0)
		)
		(polygon
			(pts
				(arc
					(start 225.58502 -134.902448)
					(mid 225.20402 -135.283448)
					(end 225.58502 -135.664448)
				)
				(arc
					(start 226.44862 -135.664448)
					(mid 226.82962 -135.283448)
					(end 226.44862 -134.902448)
				)
			)
		)
	)
	(zone
		(layers "F.Cu" "B.Cu" "In1.Cu" "In2.Cu" "In3.Cu" "In4.Cu" "In5.Cu" "In6.Cu"
			"In7.Cu" "In8.Cu" "In9.Cu" "In10.Cu" "In11.Cu" "In12.Cu" "In13.Cu" "In14.Cu"
			"In15.Cu" "In16.Cu"
		)
		(hatch none 0.5)
		(connect_pads
			(clearance 0)
		)
		(min_thickness 0.25)
		(keepout
			(tracks not_allowed)
			(vias allowed)
			(pads allowed)
			(copperpour not_allowed)
			(footprints allowed)
		)
		(placement
			(enabled no)
			(sheetname "")
		)
		(fill
			(thermal_gap 0.5)
			(thermal_bridge_width 0.5)
			(island_removal_mode 0)
		)
		(polygon
			(pts
				(arc
					(start 110.089696 -221.133924)
					(mid 109.431836 -221.133924)
					(end 110.089696 -221.133924)
				)
			)
		)
	)
	(zone
		(layers "F.Cu" "B.Cu" "In1.Cu" "In2.Cu" "In3.Cu" "In4.Cu" "In5.Cu" "In6.Cu"
			"In7.Cu" "In8.Cu" "In9.Cu" "In10.Cu" "In11.Cu" "In12.Cu" "In13.Cu" "In14.Cu"
			"In15.Cu" "In16.Cu"
		)
		(hatch none 0.5)
		(connect_pads
			(clearance 0)
		)
		(min_thickness 0.25)
		(keepout
			(tracks not_allowed)
			(vias allowed)
			(pads allowed)
			(copperpour not_allowed)
			(footprints allowed)
		)
		(placement
			(enabled no)
			(sheetname "")
		)
		(fill
			(thermal_gap 0.5)
			(thermal_bridge_width 0.5)
			(island_removal_mode 0)
		)
		(polygon
			(pts
				(arc
					(start 350.621346 -275.08073)
					(mid 349.963486 -275.08073)
					(end 350.621346 -275.08073)
				)
			)
		)
	)
	(zone
		(layers "F.Cu" "B.Cu" "In1.Cu" "In2.Cu" "In3.Cu" "In4.Cu" "In5.Cu" "In6.Cu"
			"In7.Cu" "In8.Cu" "In9.Cu" "In10.Cu" "In11.Cu" "In12.Cu" "In13.Cu" "In14.Cu"
			"In15.Cu" "In16.Cu"
		)
		(hatch none 0.5)
		(connect_pads
			(clearance 0)
		)
		(min_thickness 0.25)
		(keepout
			(tracks not_allowed)
			(vias allowed)
			(pads allowed)
			(copperpour not_allowed)
			(footprints allowed)
		)
		(placement
			(enabled no)
			(sheetname "")
		)
		(fill
			(thermal_gap 0.5)
			(thermal_bridge_width 0.5)
			(island_removal_mode 0)
		)
		(polygon
			(pts
				(arc
					(start 98.342196 -213.732618)
					(mid 97.684336 -213.732618)
					(end 98.342196 -213.732618)
				)
			)
		)
	)
	(zone
		(layers "F.Cu" "B.Cu" "In1.Cu" "In2.Cu" "In3.Cu" "In4.Cu" "In5.Cu" "In6.Cu"
			"In7.Cu" "In8.Cu" "In9.Cu" "In10.Cu" "In11.Cu" "In12.Cu" "In13.Cu" "In14.Cu"
			"In15.Cu" "In16.Cu"
		)
		(hatch none 0.5)
		(connect_pads
			(clearance 0)
		)
		(min_thickness 0.25)
		(keepout
			(tracks not_allowed)
			(vias allowed)
			(pads allowed)
			(copperpour not_allowed)
			(footprints allowed)
		)
		(placement
			(enabled no)
			(sheetname "")
		)
		(fill
			(thermal_gap 0.5)
			(thermal_bridge_width 0.5)
			(island_removal_mode 0)
		)
		(polygon
			(pts
				(arc
					(start 345.452192 -280.778204)
					(mid 344.794332 -280.778204)
					(end 345.452192 -280.778204)
				)
			)
		)
	)
	(zone
		(layers "F.Cu" "B.Cu" "In1.Cu" "In2.Cu" "In3.Cu" "In4.Cu" "In5.Cu" "In6.Cu"
			"In7.Cu" "In8.Cu" "In9.Cu" "In10.Cu" "In11.Cu" "In12.Cu" "In13.Cu" "In14.Cu"
			"In15.Cu" "In16.Cu"
		)
		(hatch none 0.5)
		(connect_pads
			(clearance 0)
		)
		(min_thickness 0.25)
		(keepout
			(tracks not_allowed)
			(vias allowed)
			(pads allowed)
			(copperpour not_allowed)
			(footprints allowed)
		)
		(placement
			(enabled no)
			(sheetname "")
		)
		(fill
			(thermal_gap 0.5)
			(thermal_bridge_width 0.5)
			(island_removal_mode 0)
		)
		(polygon
			(pts
				(arc
					(start 342.633046 -288.917126)
					(mid 341.975186 -288.917126)
					(end 342.633046 -288.917126)
				)
			)
		)
	)
	(zone
		(layers "F.Cu" "B.Cu" "In1.Cu" "In2.Cu" "In3.Cu" "In4.Cu" "In5.Cu" "In6.Cu"
			"In7.Cu" "In8.Cu" "In9.Cu" "In10.Cu" "In11.Cu" "In12.Cu" "In13.Cu" "In14.Cu"
			"In15.Cu" "In16.Cu"
		)
		(hatch none 0.5)
		(connect_pads
			(clearance 0)
		)
		(min_thickness 0.25)
		(keepout
			(tracks not_allowed)
			(vias allowed)
			(pads allowed)
			(copperpour not_allowed)
			(footprints allowed)
		)
		(placement
			(enabled no)
			(sheetname "")
		)
		(fill
			(thermal_gap 0.5)
			(thermal_bridge_width 0.5)
			(island_removal_mode 0)
		)
		(polygon
			(pts
				(arc
					(start 105.701846 -223.67367)
					(mid 105.72153 -223.62626)
					(end 105.728262 -223.575372)
				)
				(arc
					(start 105.728262 -223.575372)
					(mid 105.670606 -223.436178)
					(end 105.531412 -223.378522)
				)
				(arc
					(start 105.531412 -223.378522)
					(mid 105.432981 -223.404938)
					(end 105.360978 -223.477074)
				)
				(arc
					(start 104.891332 -224.291144)
					(mid 104.871648 -224.338554)
					(end 104.864916 -224.389442)
				)
				(arc
					(start 104.864916 -224.389442)
					(mid 104.922572 -224.528636)
					(end 105.061766 -224.586292)
				)
				(arc
					(start 105.061766 -224.586292)
					(mid 105.160197 -224.559876)
					(end 105.2322 -224.48774)
				)
			)
		)
	)
	(zone
		(layers "F.Cu" "B.Cu" "In1.Cu" "In2.Cu" "In3.Cu" "In4.Cu" "In5.Cu" "In6.Cu"
			"In7.Cu" "In8.Cu" "In9.Cu" "In10.Cu" "In11.Cu" "In12.Cu" "In13.Cu" "In14.Cu"
			"In15.Cu" "In16.Cu"
		)
		(hatch none 0.5)
		(connect_pads
			(clearance 0)
		)
		(min_thickness 0.25)
		(keepout
			(tracks not_allowed)
			(vias allowed)
			(pads allowed)
			(copperpour not_allowed)
			(footprints allowed)
		)
		(placement
			(enabled no)
			(sheetname "")
		)
		(fill
			(thermal_gap 0.5)
			(thermal_bridge_width 0.5)
			(island_removal_mode 0)
		)
		(polygon
			(pts
				(arc
					(start 354.112068 -224.291144)
					(mid 354.040079 -224.218985)
					(end 353.941634 -224.192592)
				)
				(arc
					(start 353.941634 -224.192592)
					(mid 353.80244 -224.250248)
					(end 353.744784 -224.389442)
				)
				(arc
					(start 353.744784 -224.389442)
					(mid 353.751541 -224.440323)
					(end 353.7712 -224.48774)
				)
				(arc
					(start 354.240846 -225.301556)
					(mid 354.312835 -225.373715)
					(end 354.41128 -225.400108)
				)
				(arc
					(start 354.41128 -225.400108)
					(mid 354.550474 -225.342452)
					(end 354.60813 -225.203258)
				)
				(arc
					(start 354.60813 -225.203258)
					(mid 354.601373 -225.152377)
					(end 354.581714 -225.10496)
				)
			)
		)
	)
	(zone
		(layers "F.Cu" "B.Cu" "In1.Cu" "In2.Cu" "In3.Cu" "In4.Cu" "In5.Cu" "In6.Cu"
			"In7.Cu" "In8.Cu" "In9.Cu" "In10.Cu" "In11.Cu" "In12.Cu" "In13.Cu" "In14.Cu"
			"In15.Cu" "In16.Cu"
		)
		(hatch none 0.5)
		(connect_pads
			(clearance 0)
		)
		(min_thickness 0.25)
		(keepout
			(tracks not_allowed)
			(vias allowed)
			(pads allowed)
			(copperpour not_allowed)
			(footprints allowed)
		)
		(placement
			(enabled no)
			(sheetname "")
		)
		(fill
			(thermal_gap 0.5)
			(thermal_bridge_width 0.5)
			(island_removal_mode 0)
		)
		(polygon
			(pts
				(arc
					(start 92.31376 -285.563056)
					(mid 92.294076 -285.610466)
					(end 92.287344 -285.661354)
				)
				(arc
					(start 92.287344 -285.661354)
					(mid 92.345 -285.800548)
					(end 92.484194 -285.858204)
				)
				(arc
					(start 92.484194 -285.858204)
					(mid 92.582625 -285.831788)
					(end 92.654628 -285.759652)
				)
				(arc
					(start 93.124528 -284.945582)
					(mid 93.144212 -284.898172)
					(end 93.150944 -284.847284)
				)
				(arc
					(start 93.150944 -284.847284)
					(mid 93.093288 -284.70809)
					(end 92.954094 -284.650434)
				)
				(arc
					(start 92.954094 -284.650434)
					(mid 92.855663 -284.67685)
					(end 92.78366 -284.748986)
				)
			)
		)
	)
	(zone
		(layers "F.Cu" "B.Cu" "In1.Cu" "In2.Cu" "In3.Cu" "In4.Cu" "In5.Cu" "In6.Cu"
			"In7.Cu" "In8.Cu" "In9.Cu" "In10.Cu" "In11.Cu" "In12.Cu" "In13.Cu" "In14.Cu"
			"In15.Cu" "In16.Cu"
		)
		(hatch none 0.5)
		(connect_pads
			(clearance 0)
		)
		(min_thickness 0.25)
		(keepout
			(tracks not_allowed)
			(vias allowed)
			(pads allowed)
			(copperpour not_allowed)
			(footprints allowed)
		)
		(placement
			(enabled no)
			(sheetname "")
		)
		(fill
			(thermal_gap 0.5)
			(thermal_bridge_width 0.5)
			(island_removal_mode 0)
		)
		(polygon
			(pts
				(arc
					(start 96.29648 -213.646766)
					(mid 96.228772 -213.574915)
					(end 96.133666 -213.548468)
				)
				(arc
					(start 96.133666 -213.548468)
					(mid 96.003452 -213.602404)
					(end 95.949516 -213.732618)
				)
				(arc
					(start 95.949516 -213.732618)
					(mid 95.954967 -213.776839)
					(end 95.970852 -213.81847)
				)
				(arc
					(start 96.440244 -214.708486)
					(mid 96.507952 -214.780337)
					(end 96.603058 -214.806784)
				)
				(arc
					(start 96.603058 -214.806784)
					(mid 96.733272 -214.752848)
					(end 96.787208 -214.622634)
				)
				(arc
					(start 96.787208 -214.622634)
					(mid 96.781757 -214.578413)
					(end 96.765872 -214.536782)
				)
			)
		)
	)
	(zone
		(layers "F.Cu" "B.Cu" "In1.Cu" "In2.Cu" "In3.Cu" "In4.Cu" "In5.Cu" "In6.Cu"
			"In7.Cu" "In8.Cu" "In9.Cu" "In10.Cu" "In11.Cu" "In12.Cu" "In13.Cu" "In14.Cu"
			"In15.Cu" "In16.Cu"
		)
		(hatch none 0.5)
		(connect_pads
			(clearance 0)
		)
		(min_thickness 0.25)
		(keepout
			(tracks not_allowed)
			(vias allowed)
			(pads allowed)
			(copperpour not_allowed)
			(footprints allowed)
		)
		(placement
			(enabled no)
			(sheetname "")
		)
		(fill
			(thermal_gap 0.5)
			(thermal_bridge_width 0.5)
			(island_removal_mode 0)
		)
		(polygon
			(pts
				(arc
					(start 126.927864 -285.661354)
					(mid 127.585724 -285.661354)
					(end 126.927864 -285.661354)
				)
			)
		)
	)
	(zone
		(layers "F.Cu" "B.Cu" "In1.Cu" "In2.Cu" "In3.Cu" "In4.Cu" "In5.Cu" "In6.Cu"
			"In7.Cu" "In8.Cu" "In9.Cu" "In10.Cu" "In11.Cu" "In12.Cu" "In13.Cu" "In14.Cu"
			"In15.Cu" "In16.Cu"
		)
		(hatch none 0.5)
		(connect_pads
			(clearance 0)
		)
		(min_thickness 0.25)
		(keepout
			(tracks not_allowed)
			(vias allowed)
			(pads allowed)
			(copperpour not_allowed)
			(footprints allowed)
		)
		(placement
			(enabled no)
			(sheetname "")
		)
		(fill
			(thermal_gap 0.5)
			(thermal_bridge_width 0.5)
			(island_removal_mode 0)
		)
		(polygon
			(pts
				(arc
					(start 118.388892 -221.231968)
					(mid 118.408576 -221.184558)
					(end 118.415308 -221.13367)
				)
				(arc
					(start 118.415308 -221.13367)
					(mid 118.357652 -220.994476)
					(end 118.218458 -220.93682)
				)
				(arc
					(start 118.218458 -220.93682)
					(mid 118.120027 -220.963236)
					(end 118.048024 -221.035372)
				)
				(arc
					(start 117.578378 -221.849442)
					(mid 117.558694 -221.896852)
					(end 117.551962 -221.94774)
				)
				(arc
					(start 117.551962 -221.94774)
					(mid 117.609618 -222.086934)
					(end 117.748812 -222.14459)
				)
				(arc
					(start 117.748812 -222.14459)
					(mid 117.847243 -222.118174)
					(end 117.919246 -222.046038)
				)
			)
		)
	)
	(zone
		(layers "F.Cu" "B.Cu" "In1.Cu" "In2.Cu" "In3.Cu" "In4.Cu" "In5.Cu" "In6.Cu"
			"In7.Cu" "In8.Cu" "In9.Cu" "In10.Cu" "In11.Cu" "In12.Cu" "In13.Cu" "In14.Cu"
			"In15.Cu" "In16.Cu"
		)
		(hatch none 0.5)
		(connect_pads
			(clearance 0)
		)
		(min_thickness 0.25)
		(keepout
			(tracks not_allowed)
			(vias allowed)
			(pads allowed)
			(copperpour not_allowed)
			(footprints allowed)
		)
		(placement
			(enabled no)
			(sheetname "")
		)
		(fill
			(thermal_gap 0.5)
			(thermal_bridge_width 0.5)
			(island_removal_mode 0)
		)
		(polygon
			(pts
				(arc
					(start 353.80041 -223.575626)
					(mid 353.14255 -223.575626)
					(end 353.80041 -223.575626)
				)
			)
		)
	)
	(zone
		(layers "F.Cu" "B.Cu" "In1.Cu" "In2.Cu" "In3.Cu" "In4.Cu" "In5.Cu" "In6.Cu"
			"In7.Cu" "In8.Cu" "In9.Cu" "In10.Cu" "In11.Cu" "In12.Cu" "In13.Cu" "In14.Cu"
			"In15.Cu" "In16.Cu"
		)
		(hatch none 0.5)
		(connect_pads
			(clearance 0)
		)
		(min_thickness 0.25)
		(keepout
			(tracks not_allowed)
			(vias allowed)
			(pads allowed)
			(copperpour not_allowed)
			(footprints allowed)
		)
		(placement
			(enabled no)
			(sheetname "")
		)
		(fill
			(thermal_gap 0.5)
			(thermal_bridge_width 0.5)
			(island_removal_mode 0)
		)
		(polygon
			(pts
				(arc
					(start 369.614704 -169.923968)
					(mid 369.763494 -170.283178)
					(end 370.122704 -170.431968)
				)
				(arc
					(start 370.123212 -170.431968)
					(mid 370.254421 -170.414731)
					(end 370.376704 -170.36415)
				)
				(arc
					(start 371.300756 -169.830496)
					(mid 371.486689 -169.64456)
					(end 371.554756 -169.390568)
				)
				(arc
					(start 371.554756 -169.390568)
					(mid 371.405966 -169.031358)
					(end 371.046756 -168.882568)
				)
				(arc
					(start 371.046248 -168.882568)
					(mid 370.915039 -168.899805)
					(end 370.792756 -168.950386)
				)
				(arc
					(start 369.868704 -169.48404)
					(mid 369.682771 -169.669976)
					(end 369.614704 -169.923968)
				)
			)
		)
	)
	(zone
		(layers "F.Cu" "B.Cu" "In1.Cu" "In2.Cu" "In3.Cu" "In4.Cu" "In5.Cu" "In6.Cu"
			"In7.Cu" "In8.Cu" "In9.Cu" "In10.Cu" "In11.Cu" "In12.Cu" "In13.Cu" "In14.Cu"
			"In15.Cu" "In16.Cu"
		)
		(hatch none 0.5)
		(connect_pads
			(clearance 0)
		)
		(min_thickness 0.25)
		(keepout
			(tracks not_allowed)
			(vias allowed)
			(pads allowed)
			(copperpour not_allowed)
			(footprints allowed)
		)
		(placement
			(enabled no)
			(sheetname "")
		)
		(fill
			(thermal_gap 0.5)
			(thermal_bridge_width 0.5)
			(island_removal_mode 0)
		)
		(polygon
			(pts
				(arc
					(start 372.437914 -223.67367)
					(mid 372.457598 -223.62626)
					(end 372.46433 -223.575372)
				)
				(arc
					(start 372.46433 -223.575372)
					(mid 372.406674 -223.436178)
					(end 372.26748 -223.378522)
				)
				(arc
					(start 372.26748 -223.378522)
					(mid 372.169049 -223.404938)
					(end 372.097046 -223.477074)
				)
				(arc
					(start 371.6274 -224.291144)
					(mid 371.607716 -224.338554)
					(end 371.600984 -224.389442)
				)
				(arc
					(start 371.600984 -224.389442)
					(mid 371.65864 -224.528636)
					(end 371.797834 -224.586292)
				)
				(arc
					(start 371.797834 -224.586292)
					(mid 371.896265 -224.559876)
					(end 371.968268 -224.48774)
				)
			)
		)
	)
	(zone
		(layers "F.Cu" "B.Cu" "In1.Cu" "In2.Cu" "In3.Cu" "In4.Cu" "In5.Cu" "In6.Cu"
			"In7.Cu" "In8.Cu" "In9.Cu" "In10.Cu" "In11.Cu" "In12.Cu" "In13.Cu" "In14.Cu"
			"In15.Cu" "In16.Cu"
		)
		(hatch none 0.5)
		(connect_pads
			(clearance 0)
		)
		(min_thickness 0.25)
		(keepout
			(tracks not_allowed)
			(vias allowed)
			(pads allowed)
			(copperpour not_allowed)
			(footprints allowed)
		)
		(placement
			(enabled no)
			(sheetname "")
		)
		(fill
			(thermal_gap 0.5)
			(thermal_bridge_width 0.5)
			(island_removal_mode 0)
		)
		(polygon
			(pts
				(arc
					(start 376.35561 -217.064336)
					(mid 375.69775 -217.064336)
					(end 376.35561 -217.064336)
				)
			)
		)
	)
	(zone
		(layers "F.Cu" "B.Cu" "In1.Cu" "In2.Cu" "In3.Cu" "In4.Cu" "In5.Cu" "In6.Cu"
			"In7.Cu" "In8.Cu" "In9.Cu" "In10.Cu" "In11.Cu" "In12.Cu" "In13.Cu" "In14.Cu"
			"In15.Cu" "In16.Cu"
		)
		(hatch none 0.5)
		(connect_pads
			(clearance 0)
		)
		(min_thickness 0.25)
		(keepout
			(tracks not_allowed)
			(vias allowed)
			(pads allowed)
			(copperpour not_allowed)
			(footprints allowed)
		)
		(placement
			(enabled no)
			(sheetname "")
		)
		(fill
			(thermal_gap 0.5)
			(thermal_bridge_width 0.5)
			(island_removal_mode 0)
		)
		(polygon
			(pts
				(arc
					(start 128.24968 -213.646766)
					(mid 128.181972 -213.574915)
					(end 128.086866 -213.548468)
				)
				(arc
					(start 128.086866 -213.548468)
					(mid 127.956652 -213.602404)
					(end 127.902716 -213.732618)
				)
				(arc
					(start 127.902716 -213.732618)
					(mid 127.908167 -213.776839)
					(end 127.924052 -213.81847)
				)
				(arc
					(start 128.393444 -214.708486)
					(mid 128.461152 -214.780337)
					(end 128.556258 -214.806784)
				)
				(arc
					(start 128.556258 -214.806784)
					(mid 128.686472 -214.752848)
					(end 128.740408 -214.622634)
				)
				(arc
					(start 128.740408 -214.622634)
					(mid 128.734957 -214.578413)
					(end 128.719072 -214.536782)
				)
			)
		)
	)
	(zone
		(layers "F.Cu" "B.Cu" "In1.Cu" "In2.Cu" "In3.Cu" "In4.Cu" "In5.Cu" "In6.Cu"
			"In7.Cu" "In8.Cu" "In9.Cu" "In10.Cu" "In11.Cu" "In12.Cu" "In13.Cu" "In14.Cu"
			"In15.Cu" "In16.Cu"
		)
		(hatch none 0.5)
		(connect_pads
			(clearance 0)
		)
		(min_thickness 0.25)
		(keepout
			(tracks not_allowed)
			(vias allowed)
			(pads allowed)
			(copperpour not_allowed)
			(footprints allowed)
		)
		(placement
			(enabled no)
			(sheetname "")
		)
		(fill
			(thermal_gap 0.5)
			(thermal_bridge_width 0.5)
			(island_removal_mode 0)
		)
		(polygon
			(pts
				(arc
					(start 118.547388 -214.622634)
					(mid 117.889528 -214.622634)
					(end 118.547388 -214.622634)
				)
			)
		)
	)
	(zone
		(layers "F.Cu" "B.Cu" "In1.Cu" "In2.Cu" "In3.Cu" "In4.Cu" "In5.Cu" "In6.Cu"
			"In7.Cu" "In8.Cu" "In9.Cu" "In10.Cu" "In11.Cu" "In12.Cu" "In13.Cu" "In14.Cu"
			"In15.Cu" "In16.Cu"
		)
		(hatch none 0.5)
		(connect_pads
			(clearance 0)
		)
		(min_thickness 0.25)
		(keepout
			(tracks not_allowed)
			(vias allowed)
			(pads allowed)
			(copperpour not_allowed)
			(footprints allowed)
		)
		(placement
			(enabled no)
			(sheetname "")
		)
		(fill
			(thermal_gap 0.5)
			(thermal_bridge_width 0.5)
			(island_removal_mode 0)
		)
		(polygon
			(pts
				(arc
					(start 350.621346 -283.219906)
					(mid 349.963486 -283.219906)
					(end 350.621346 -283.219906)
				)
			)
		)
	)
	(zone
		(layers "F.Cu" "B.Cu" "In1.Cu" "In2.Cu" "In3.Cu" "In4.Cu" "In5.Cu" "In6.Cu"
			"In7.Cu" "In8.Cu" "In9.Cu" "In10.Cu" "In11.Cu" "In12.Cu" "In13.Cu" "In14.Cu"
			"In15.Cu" "In16.Cu"
		)
		(hatch none 0.5)
		(connect_pads
			(clearance 0)
		)
		(min_thickness 0.25)
		(keepout
			(tracks not_allowed)
			(vias allowed)
			(pads allowed)
			(copperpour not_allowed)
			(footprints allowed)
		)
		(placement
			(enabled no)
			(sheetname "")
		)
		(fill
			(thermal_gap 0.5)
			(thermal_bridge_width 0.5)
			(island_removal_mode 0)
		)
		(polygon
			(pts
				(arc
					(start 340.01456 -214.720932)
					(mid 340.034244 -214.673522)
					(end 340.040976 -214.622634)
				)
				(arc
					(start 340.040976 -214.622634)
					(mid 339.98332 -214.48344)
					(end 339.844126 -214.425784)
				)
				(arc
					(start 339.844126 -214.425784)
					(mid 339.745695 -214.4522)
					(end 339.673692 -214.524336)
				)
				(arc
					(start 339.204046 -215.338406)
					(mid 339.184362 -215.385816)
					(end 339.17763 -215.436704)
				)
				(arc
					(start 339.17763 -215.436704)
					(mid 339.235286 -215.575898)
					(end 339.37448 -215.633554)
				)
				(arc
					(start 339.37448 -215.633554)
					(mid 339.472911 -215.607138)
					(end 339.544914 -215.535002)
				)
			)
		)
	)
	(zone
		(layers "F.Cu" "B.Cu" "In1.Cu" "In2.Cu" "In3.Cu" "In4.Cu" "In5.Cu" "In6.Cu"
			"In7.Cu" "In8.Cu" "In9.Cu" "In10.Cu" "In11.Cu" "In12.Cu" "In13.Cu" "In14.Cu"
			"In15.Cu" "In16.Cu"
		)
		(hatch none 0.5)
		(connect_pads
			(clearance 0)
		)
		(min_thickness 0.25)
		(keepout
			(tracks not_allowed)
			(vias allowed)
			(pads allowed)
			(copperpour not_allowed)
			(footprints allowed)
		)
		(placement
			(enabled no)
			(sheetname "")
		)
		(fill
			(thermal_gap 0.5)
			(thermal_bridge_width 0.5)
			(island_removal_mode 0)
		)
		(polygon
			(pts
				(arc
					(start 366.487964 -224.389442)
					(mid 365.830104 -224.389442)
					(end 366.487964 -224.389442)
				)
			)
		)
	)
	(zone
		(layers "F.Cu" "B.Cu" "In1.Cu" "In2.Cu" "In3.Cu" "In4.Cu" "In5.Cu" "In6.Cu"
			"In7.Cu" "In8.Cu" "In9.Cu" "In10.Cu" "In11.Cu" "In12.Cu" "In13.Cu" "In14.Cu"
			"In15.Cu" "In16.Cu"
		)
		(hatch none 0.5)
		(connect_pads
			(clearance 0)
		)
		(min_thickness 0.25)
		(keepout
			(tracks not_allowed)
			(vias allowed)
			(pads allowed)
			(copperpour not_allowed)
			(footprints allowed)
		)
		(placement
			(enabled no)
			(sheetname "")
		)
		(fill
			(thermal_gap 0.5)
			(thermal_bridge_width 0.5)
			(island_removal_mode 0)
		)
		(polygon
			(pts
				(arc
					(start 103.822246 -220.418152)
					(mid 103.84193 -220.370742)
					(end 103.848662 -220.319854)
				)
				(arc
					(start 103.848662 -220.319854)
					(mid 103.791006 -220.18066)
					(end 103.651812 -220.123004)
				)
				(arc
					(start 103.651812 -220.123004)
					(mid 103.553381 -220.14942)
					(end 103.481378 -220.221556)
				)
				(arc
					(start 103.011732 -221.035626)
					(mid 102.992048 -221.083036)
					(end 102.985316 -221.133924)
				)
				(arc
					(start 102.985316 -221.133924)
					(mid 103.042972 -221.273118)
					(end 103.182166 -221.330774)
				)
				(arc
					(start 103.182166 -221.330774)
					(mid 103.280597 -221.304358)
					(end 103.3526 -221.232222)
				)
			)
		)
	)
	(zone
		(layers "F.Cu" "B.Cu" "In1.Cu" "In2.Cu" "In3.Cu" "In4.Cu" "In5.Cu" "In6.Cu"
			"In7.Cu" "In8.Cu" "In9.Cu" "In10.Cu" "In11.Cu" "In12.Cu" "In13.Cu" "In14.Cu"
			"In15.Cu" "In16.Cu"
		)
		(hatch none 0.5)
		(connect_pads
			(clearance 0)
		)
		(min_thickness 0.25)
		(keepout
			(tracks not_allowed)
			(vias allowed)
			(pads allowed)
			(copperpour not_allowed)
			(footprints allowed)
		)
		(placement
			(enabled no)
			(sheetname "")
		)
		(fill
			(thermal_gap 0.5)
			(thermal_bridge_width 0.5)
			(island_removal_mode 0)
		)
		(polygon
			(pts
				(arc
					(start 96.774 -221.035626)
					(mid 96.702011 -220.963467)
					(end 96.603566 -220.937074)
				)
				(arc
					(start 96.603566 -220.937074)
					(mid 96.464372 -220.99473)
					(end 96.406716 -221.133924)
				)
				(arc
					(start 96.406716 -221.133924)
					(mid 96.413473 -221.184805)
					(end 96.433132 -221.232222)
				)
				(arc
					(start 96.902778 -222.046038)
					(mid 96.974767 -222.118197)
					(end 97.073212 -222.14459)
				)
				(arc
					(start 97.073212 -222.14459)
					(mid 97.212406 -222.086934)
					(end 97.270062 -221.94774)
				)
				(arc
					(start 97.270062 -221.94774)
					(mid 97.263305 -221.896859)
					(end 97.243646 -221.849442)
				)
			)
		)
	)
	(zone
		(layers "F.Cu" "B.Cu" "In1.Cu" "In2.Cu" "In3.Cu" "In4.Cu" "In5.Cu" "In6.Cu"
			"In7.Cu" "In8.Cu" "In9.Cu" "In10.Cu" "In11.Cu" "In12.Cu" "In13.Cu" "In14.Cu"
			"In15.Cu" "In16.Cu"
		)
		(hatch none 0.5)
		(connect_pads
			(clearance 0)
		)
		(min_thickness 0.25)
		(keepout
			(tracks not_allowed)
			(vias allowed)
			(pads allowed)
			(copperpour not_allowed)
			(footprints allowed)
		)
		(placement
			(enabled no)
			(sheetname "")
		)
		(fill
			(thermal_gap 0.5)
			(thermal_bridge_width 0.5)
			(island_removal_mode 0)
		)
		(polygon
			(pts
				(arc
					(start 111.969296 -224.389442)
					(mid 111.311436 -224.389442)
					(end 111.969296 -224.389442)
				)
			)
		)
	)
	(zone
		(layers "F.Cu" "B.Cu" "In1.Cu" "In2.Cu" "In3.Cu" "In4.Cu" "In5.Cu" "In6.Cu"
			"In7.Cu" "In8.Cu" "In9.Cu" "In10.Cu" "In11.Cu" "In12.Cu" "In13.Cu" "In14.Cu"
			"In15.Cu" "In16.Cu"
		)
		(hatch none 0.5)
		(connect_pads
			(clearance 0)
		)
		(min_thickness 0.25)
		(keepout
			(tracks not_allowed)
			(vias allowed)
			(pads allowed)
			(copperpour not_allowed)
			(footprints allowed)
		)
		(placement
			(enabled no)
			(sheetname "")
		)
		(fill
			(thermal_gap 0.5)
			(thermal_bridge_width 0.5)
			(island_removal_mode 0)
		)
		(polygon
			(pts
				(arc
					(start 340.894162 -283.023056)
					(mid 340.697312 -283.219906)
					(end 340.894162 -283.416756)
				)
				(arc
					(start 341.833962 -283.416756)
					(mid 342.030812 -283.219906)
					(end 341.833962 -283.023056)
				)
			)
		)
	)
	(zone
		(layers "F.Cu" "B.Cu" "In1.Cu" "In2.Cu" "In3.Cu" "In4.Cu" "In5.Cu" "In6.Cu"
			"In7.Cu" "In8.Cu" "In9.Cu" "In10.Cu" "In11.Cu" "In12.Cu" "In13.Cu" "In14.Cu"
			"In15.Cu" "In16.Cu"
		)
		(hatch none 0.5)
		(connect_pads
			(clearance 0)
		)
		(min_thickness 0.25)
		(keepout
			(tracks not_allowed)
			(vias allowed)
			(pads allowed)
			(copperpour not_allowed)
			(footprints allowed)
		)
		(placement
			(enabled no)
			(sheetname "")
		)
		(fill
			(thermal_gap 0.5)
			(thermal_bridge_width 0.5)
			(island_removal_mode 0)
		)
		(polygon
			(pts
				(arc
					(start 390.041384 -17.220438)
					(mid 389.660384 -17.601438)
					(end 390.041384 -17.982438)
				)
				(arc
					(start 390.904984 -17.982438)
					(mid 391.285984 -17.601438)
					(end 390.904984 -17.220438)
				)
			)
		)
	)
	(zone
		(layers "F.Cu" "B.Cu" "In1.Cu" "In2.Cu" "In3.Cu" "In4.Cu" "In5.Cu" "In6.Cu"
			"In7.Cu" "In8.Cu" "In9.Cu" "In10.Cu" "In11.Cu" "In12.Cu" "In13.Cu" "In14.Cu"
			"In15.Cu" "In16.Cu"
		)
		(hatch none 0.5)
		(connect_pads
			(clearance 0)
		)
		(min_thickness 0.25)
		(keepout
			(tracks not_allowed)
			(vias allowed)
			(pads allowed)
			(copperpour not_allowed)
			(footprints allowed)
		)
		(placement
			(enabled no)
			(sheetname "")
		)
		(fill
			(thermal_gap 0.5)
			(thermal_bridge_width 0.5)
			(island_removal_mode 0)
		)
		(polygon
			(pts
				(arc
					(start 374.831356 -168.018968)
					(mid 375.190566 -167.870178)
					(end 375.339356 -167.510968)
				)
				(arc
					(start 375.339356 -167.510968)
					(mid 375.271299 -167.256971)
					(end 375.085356 -167.07104)
				)
				(arc
					(start 374.161304 -166.537386)
					(mid 374.03901 -166.486849)
					(end 373.907812 -166.469568)
				)
				(arc
					(start 373.907304 -166.469568)
					(mid 373.548094 -166.618358)
					(end 373.399304 -166.977568)
				)
				(arc
					(start 373.399304 -166.977568)
					(mid 373.467361 -167.231565)
					(end 373.653304 -167.417496)
				)
				(arc
					(start 374.577356 -167.95115)
					(mid 374.69965 -168.001687)
					(end 374.830848 -168.018968)
				)
			)
		)
	)
	(zone
		(layers "F.Cu" "B.Cu" "In1.Cu" "In2.Cu" "In3.Cu" "In4.Cu" "In5.Cu" "In6.Cu"
			"In7.Cu" "In8.Cu" "In9.Cu" "In10.Cu" "In11.Cu" "In12.Cu" "In13.Cu" "In14.Cu"
			"In15.Cu" "In16.Cu"
		)
		(hatch none 0.5)
		(connect_pads
			(clearance 0)
		)
		(min_thickness 0.25)
		(keepout
			(tracks not_allowed)
			(vias allowed)
			(pads allowed)
			(copperpour not_allowed)
			(footprints allowed)
		)
		(placement
			(enabled no)
			(sheetname "")
		)
		(fill
			(thermal_gap 0.5)
			(thermal_bridge_width 0.5)
			(island_removal_mode 0)
		)
		(polygon
			(pts
				(arc
					(start 112.909096 -224.389442)
					(mid 112.251236 -224.389442)
					(end 112.909096 -224.389442)
				)
			)
		)
	)
	(zone
		(layers "F.Cu" "B.Cu" "In1.Cu" "In2.Cu" "In3.Cu" "In4.Cu" "In5.Cu" "In6.Cu"
			"In7.Cu" "In8.Cu" "In9.Cu" "In10.Cu" "In11.Cu" "In12.Cu" "In13.Cu" "In14.Cu"
			"In15.Cu" "In16.Cu"
		)
		(hatch none 0.5)
		(connect_pads
			(clearance 0)
		)
		(min_thickness 0.25)
		(keepout
			(tracks not_allowed)
			(vias allowed)
			(pads allowed)
			(copperpour not_allowed)
			(footprints allowed)
		)
		(placement
			(enabled no)
			(sheetname "")
		)
		(fill
			(thermal_gap 0.5)
			(thermal_bridge_width 0.5)
			(island_removal_mode 0)
		)
		(polygon
			(pts
				(arc
					(start 119.017542 -223.575626)
					(mid 118.359682 -223.575626)
					(end 119.017542 -223.575626)
				)
			)
		)
	)
	(zone
		(layers "F.Cu" "B.Cu" "In1.Cu" "In2.Cu" "In3.Cu" "In4.Cu" "In5.Cu" "In6.Cu"
			"In7.Cu" "In8.Cu" "In9.Cu" "In10.Cu" "In11.Cu" "In12.Cu" "In13.Cu" "In14.Cu"
			"In15.Cu" "In16.Cu"
		)
		(hatch none 0.5)
		(connect_pads
			(clearance 0)
		)
		(min_thickness 0.25)
		(keepout
			(tracks not_allowed)
			(vias allowed)
			(pads allowed)
			(copperpour not_allowed)
			(footprints allowed)
		)
		(placement
			(enabled no)
			(sheetname "")
		)
		(fill
			(thermal_gap 0.5)
			(thermal_bridge_width 0.5)
			(island_removal_mode 0)
		)
		(polygon
			(pts
				(arc
					(start 92.233496 -221.133924)
					(mid 91.575636 -221.133924)
					(end 92.233496 -221.133924)
				)
			)
		)
	)
	(zone
		(layers "F.Cu" "B.Cu" "In1.Cu" "In2.Cu" "In3.Cu" "In4.Cu" "In5.Cu" "In6.Cu"
			"In7.Cu" "In8.Cu" "In9.Cu" "In10.Cu" "In11.Cu" "In12.Cu" "In13.Cu" "In14.Cu"
			"In15.Cu" "In16.Cu"
		)
		(hatch none 0.5)
		(connect_pads
			(clearance 0)
		)
		(min_thickness 0.25)
		(keepout
			(tracks not_allowed)
			(vias allowed)
			(pads allowed)
			(copperpour not_allowed)
			(footprints allowed)
		)
		(placement
			(enabled no)
			(sheetname "")
		)
		(fill
			(thermal_gap 0.5)
			(thermal_bridge_width 0.5)
			(island_removal_mode 0)
		)
		(polygon
			(pts
				(arc
					(start 381.836422 -220.22181)
					(mid 381.764433 -220.149651)
					(end 381.665988 -220.123258)
				)
				(arc
					(start 381.665988 -220.123258)
					(mid 381.526794 -220.180914)
					(end 381.469138 -220.320108)
				)
				(arc
					(start 381.469138 -220.320108)
					(mid 381.475895 -220.370989)
					(end 381.495554 -220.418406)
				)
				(arc
					(start 381.9652 -221.232222)
					(mid 382.037189 -221.304381)
					(end 382.135634 -221.330774)
				)
				(arc
					(start 382.135634 -221.330774)
					(mid 382.274828 -221.273118)
					(end 382.332484 -221.133924)
				)
				(arc
					(start 382.332484 -221.133924)
					(mid 382.325727 -221.083043)
					(end 382.306068 -221.035626)
				)
			)
		)
	)
	(zone
		(layers "F.Cu" "B.Cu" "In1.Cu" "In2.Cu" "In3.Cu" "In4.Cu" "In5.Cu" "In6.Cu"
			"In7.Cu" "In8.Cu" "In9.Cu" "In10.Cu" "In11.Cu" "In12.Cu" "In13.Cu" "In14.Cu"
			"In15.Cu" "In16.Cu"
		)
		(hatch none 0.5)
		(connect_pads
			(clearance 0)
		)
		(min_thickness 0.25)
		(keepout
			(tracks not_allowed)
			(vias allowed)
			(pads allowed)
			(copperpour not_allowed)
			(footprints allowed)
		)
		(placement
			(enabled no)
			(sheetname "")
		)
		(fill
			(thermal_gap 0.5)
			(thermal_bridge_width 0.5)
			(island_removal_mode 0)
		)
		(polygon
			(pts
				(arc
					(start 117.138196 -213.732618)
					(mid 116.480336 -213.732618)
					(end 117.138196 -213.732618)
				)
			)
		)
	)
	(zone
		(layers "F.Cu" "B.Cu" "In1.Cu" "In2.Cu" "In3.Cu" "In4.Cu" "In5.Cu" "In6.Cu"
			"In7.Cu" "In8.Cu" "In9.Cu" "In10.Cu" "In11.Cu" "In12.Cu" "In13.Cu" "In14.Cu"
			"In15.Cu" "In16.Cu"
		)
		(hatch none 0.5)
		(connect_pads
			(clearance 0)
		)
		(min_thickness 0.25)
		(keepout
			(tracks not_allowed)
			(vias allowed)
			(pads allowed)
			(copperpour not_allowed)
			(footprints allowed)
		)
		(placement
			(enabled no)
			(sheetname "")
		)
		(fill
			(thermal_gap 0.5)
			(thermal_bridge_width 0.5)
			(island_removal_mode 0)
		)
		(polygon
			(pts
				(arc
					(start 113.848388 -214.546434)
					(mid 113.190528 -214.546434)
					(end 113.848388 -214.546434)
				)
			)
		)
	)
	(zone
		(layers "F.Cu" "B.Cu" "In1.Cu" "In2.Cu" "In3.Cu" "In4.Cu" "In5.Cu" "In6.Cu"
			"In7.Cu" "In8.Cu" "In9.Cu" "In10.Cu" "In11.Cu" "In12.Cu" "In13.Cu" "In14.Cu"
			"In15.Cu" "In16.Cu"
		)
		(hatch none 0.5)
		(connect_pads
			(clearance 0)
		)
		(min_thickness 0.25)
		(keepout
			(tracks not_allowed)
			(vias allowed)
			(pads allowed)
			(copperpour not_allowed)
			(footprints allowed)
		)
		(placement
			(enabled no)
			(sheetname "")
		)
		(fill
			(thermal_gap 0.5)
			(thermal_bridge_width 0.5)
			(island_removal_mode 0)
		)
		(polygon
			(pts
				(arc
					(start 116.480082 -220.319854)
					(mid 117.137942 -220.319854)
					(end 116.480082 -220.319854)
				)
			)
		)
	)
	(zone
		(layers "F.Cu" "B.Cu" "In1.Cu" "In2.Cu" "In3.Cu" "In4.Cu" "In5.Cu" "In6.Cu"
			"In7.Cu" "In8.Cu" "In9.Cu" "In10.Cu" "In11.Cu" "In12.Cu" "In13.Cu" "In14.Cu"
			"In15.Cu" "In16.Cu"
		)
		(hatch none 0.5)
		(connect_pads
			(clearance 0)
		)
		(min_thickness 0.25)
		(keepout
			(tracks not_allowed)
			(vias allowed)
			(pads allowed)
			(copperpour not_allowed)
			(footprints allowed)
		)
		(placement
			(enabled no)
			(sheetname "")
		)
		(fill
			(thermal_gap 0.5)
			(thermal_bridge_width 0.5)
			(island_removal_mode 0)
		)
		(polygon
			(pts
				(arc
					(start 344.042746 -281.59202)
					(mid 343.384886 -281.59202)
					(end 344.042746 -281.59202)
				)
			)
		)
	)
	(zone
		(layers "F.Cu" "B.Cu" "In1.Cu" "In2.Cu" "In3.Cu" "In4.Cu" "In5.Cu" "In6.Cu"
			"In7.Cu" "In8.Cu" "In9.Cu" "In10.Cu" "In11.Cu" "In12.Cu" "In13.Cu" "In14.Cu"
			"In15.Cu" "In16.Cu"
		)
		(hatch none 0.5)
		(connect_pads
			(clearance 0)
		)
		(min_thickness 0.25)
		(keepout
			(tracks not_allowed)
			(vias allowed)
			(pads allowed)
			(copperpour not_allowed)
			(footprints allowed)
		)
		(placement
			(enabled no)
			(sheetname "")
		)
		(fill
			(thermal_gap 0.5)
			(thermal_bridge_width 0.5)
			(island_removal_mode 0)
		)
		(polygon
			(pts
				(arc
					(start 343.41435 -285.563056)
					(mid 343.342361 -285.490897)
					(end 343.243916 -285.464504)
				)
				(arc
					(start 343.243916 -285.464504)
					(mid 343.104722 -285.52216)
					(end 343.047066 -285.661354)
				)
				(arc
					(start 343.047066 -285.661354)
					(mid 343.053823 -285.712235)
					(end 343.073482 -285.759652)
				)
				(arc
					(start 343.543382 -286.573722)
					(mid 343.615371 -286.645881)
					(end 343.713816 -286.672274)
				)
				(arc
					(start 343.713816 -286.672274)
					(mid 343.85301 -286.614618)
					(end 343.910666 -286.475424)
				)
				(arc
					(start 343.910666 -286.475424)
					(mid 343.903909 -286.424543)
					(end 343.88425 -286.377126)
				)
			)
		)
	)
	(zone
		(layers "F.Cu" "B.Cu" "In1.Cu" "In2.Cu" "In3.Cu" "In4.Cu" "In5.Cu" "In6.Cu"
			"In7.Cu" "In8.Cu" "In9.Cu" "In10.Cu" "In11.Cu" "In12.Cu" "In13.Cu" "In14.Cu"
			"In15.Cu" "In16.Cu"
		)
		(hatch none 0.5)
		(connect_pads
			(clearance 0)
		)
		(min_thickness 0.25)
		(keepout
			(tracks not_allowed)
			(vias allowed)
			(pads allowed)
			(copperpour not_allowed)
			(footprints allowed)
		)
		(placement
			(enabled no)
			(sheetname "")
		)
		(fill
			(thermal_gap 0.5)
			(thermal_bridge_width 0.5)
			(island_removal_mode 0)
		)
		(polygon
			(pts
				(arc
					(start 96.932496 -217.878406)
					(mid 96.274636 -217.878406)
					(end 96.932496 -217.878406)
				)
			)
		)
	)
	(zone
		(layers "F.Cu" "B.Cu" "In1.Cu" "In2.Cu" "In3.Cu" "In4.Cu" "In5.Cu" "In6.Cu"
			"In7.Cu" "In8.Cu" "In9.Cu" "In10.Cu" "In11.Cu" "In12.Cu" "In13.Cu" "In14.Cu"
			"In15.Cu" "In16.Cu"
		)
		(hatch none 0.5)
		(connect_pads
			(clearance 0)
		)
		(min_thickness 0.25)
		(keepout
			(tracks not_allowed)
			(vias allowed)
			(pads allowed)
			(copperpour not_allowed)
			(footprints allowed)
		)
		(placement
			(enabled no)
			(sheetname "")
		)
		(fill
			(thermal_gap 0.5)
			(thermal_bridge_width 0.5)
			(island_removal_mode 0)
		)
		(polygon
			(pts
				(arc
					(start 379.284992 -285.661354)
					(mid 378.627132 -285.661354)
					(end 379.284992 -285.661354)
				)
			)
		)
	)
	(zone
		(layers "F.Cu" "B.Cu" "In1.Cu" "In2.Cu" "In3.Cu" "In4.Cu" "In5.Cu" "In6.Cu"
			"In7.Cu" "In8.Cu" "In9.Cu" "In10.Cu" "In11.Cu" "In12.Cu" "In13.Cu" "In14.Cu"
			"In15.Cu" "In16.Cu"
		)
		(hatch none 0.5)
		(connect_pads
			(clearance 0)
		)
		(min_thickness 0.25)
		(keepout
			(tracks not_allowed)
			(vias allowed)
			(pads allowed)
			(copperpour not_allowed)
			(footprints allowed)
		)
		(placement
			(enabled no)
			(sheetname "")
		)
		(fill
			(thermal_gap 0.5)
			(thermal_bridge_width 0.5)
			(island_removal_mode 0)
		)
		(polygon
			(pts
				(arc
					(start 261.856982 -0.048006)
					(mid 262.237982 -0.429006)
					(end 262.618982 -0.048006)
				)
				(arc
					(start 262.618982 0.815594)
					(mid 262.237982 1.196594)
					(end 261.856982 0.815594)
				)
			)
		)
	)
	(zone
		(layers "F.Cu" "B.Cu" "In1.Cu" "In2.Cu" "In3.Cu" "In4.Cu" "In5.Cu" "In6.Cu"
			"In7.Cu" "In8.Cu" "In9.Cu" "In10.Cu" "In11.Cu" "In12.Cu" "In13.Cu" "In14.Cu"
			"In15.Cu" "In16.Cu"
		)
		(hatch none 0.5)
		(connect_pads
			(clearance 0)
		)
		(min_thickness 0.25)
		(keepout
			(tracks not_allowed)
			(vias allowed)
			(pads allowed)
			(copperpour not_allowed)
			(footprints allowed)
		)
		(placement
			(enabled no)
			(sheetname "")
		)
		(fill
			(thermal_gap 0.5)
			(thermal_bridge_width 0.5)
			(island_removal_mode 0)
		)
		(polygon
			(pts
				(arc
					(start 334.644492 -286.475424)
					(mid 333.986632 -286.475424)
					(end 334.644492 -286.475424)
				)
			)
		)
	)
	(zone
		(layers "F.Cu" "B.Cu" "In1.Cu" "In2.Cu" "In3.Cu" "In4.Cu" "In5.Cu" "In6.Cu"
			"In7.Cu" "In8.Cu" "In9.Cu" "In10.Cu" "In11.Cu" "In12.Cu" "In13.Cu" "In14.Cu"
			"In15.Cu" "In16.Cu"
		)
		(hatch none 0.5)
		(connect_pads
			(clearance 0)
		)
		(min_thickness 0.25)
		(keepout
			(tracks not_allowed)
			(vias allowed)
			(pads allowed)
			(copperpour not_allowed)
			(footprints allowed)
		)
		(placement
			(enabled no)
			(sheetname "")
		)
		(fill
			(thermal_gap 0.5)
			(thermal_bridge_width 0.5)
			(island_removal_mode 0)
		)
		(polygon
			(pts
				(arc
					(start 374.42013 -289.003232)
					(mid 374.436054 -288.961481)
					(end 374.441466 -288.917126)
				)
				(arc
					(start 374.441466 -288.917126)
					(mid 374.38753 -288.786912)
					(end 374.257316 -288.732976)
				)
				(arc
					(start 374.257316 -288.732976)
					(mid 374.162296 -288.759384)
					(end 374.094502 -288.83102)
				)
				(arc
					(start 373.624348 -289.721036)
					(mid 373.608424 -289.762787)
					(end 373.603012 -289.807142)
				)
				(arc
					(start 373.603012 -289.807142)
					(mid 373.656948 -289.937356)
					(end 373.787162 -289.991292)
				)
				(arc
					(start 373.787162 -289.991292)
					(mid 373.882182 -289.964884)
					(end 373.949976 -289.893248)
				)
			)
		)
	)
	(zone
		(layers "F.Cu" "B.Cu" "In1.Cu" "In2.Cu" "In3.Cu" "In4.Cu" "In5.Cu" "In6.Cu"
			"In7.Cu" "In8.Cu" "In9.Cu" "In10.Cu" "In11.Cu" "In12.Cu" "In13.Cu" "In14.Cu"
			"In15.Cu" "In16.Cu"
		)
		(hatch none 0.5)
		(connect_pads
			(clearance 0)
		)
		(min_thickness 0.25)
		(keepout
			(tracks not_allowed)
			(vias allowed)
			(pads allowed)
			(copperpour not_allowed)
			(footprints allowed)
		)
		(placement
			(enabled no)
			(sheetname "")
		)
		(fill
			(thermal_gap 0.5)
			(thermal_bridge_width 0.5)
			(island_removal_mode 0)
		)
		(polygon
			(pts
				(arc
					(start 108.210096 -224.389442)
					(mid 107.552236 -224.389442)
					(end 108.210096 -224.389442)
				)
			)
		)
	)
	(zone
		(layers "F.Cu" "B.Cu" "In1.Cu" "In2.Cu" "In3.Cu" "In4.Cu" "In5.Cu" "In6.Cu"
			"In7.Cu" "In8.Cu" "In9.Cu" "In10.Cu" "In11.Cu" "In12.Cu" "In13.Cu" "In14.Cu"
			"In15.Cu" "In16.Cu"
		)
		(hatch none 0.5)
		(connect_pads
			(clearance 0)
		)
		(min_thickness 0.25)
		(keepout
			(tracks not_allowed)
			(vias allowed)
			(pads allowed)
			(copperpour not_allowed)
			(footprints allowed)
		)
		(placement
			(enabled no)
			(sheetname "")
		)
		(fill
			(thermal_gap 0.5)
			(thermal_bridge_width 0.5)
			(island_removal_mode 0)
		)
		(polygon
			(pts
				(arc
					(start 12.499848 -115.087908)
					(mid 12.880848 -114.706908)
					(end 12.499848 -114.325908)
				)
				(arc
					(start 11.636248 -114.325908)
					(mid 11.255248 -114.706908)
					(end 11.636248 -115.087908)
				)
			)
		)
	)
	(zone
		(layers "F.Cu" "B.Cu" "In1.Cu" "In2.Cu" "In3.Cu" "In4.Cu" "In5.Cu" "In6.Cu"
			"In7.Cu" "In8.Cu" "In9.Cu" "In10.Cu" "In11.Cu" "In12.Cu" "In13.Cu" "In14.Cu"
			"In15.Cu" "In16.Cu"
		)
		(hatch none 0.5)
		(connect_pads
			(clearance 0)
		)
		(min_thickness 0.25)
		(keepout
			(tracks not_allowed)
			(vias allowed)
			(pads allowed)
			(copperpour not_allowed)
			(footprints allowed)
		)
		(placement
			(enabled no)
			(sheetname "")
		)
		(fill
			(thermal_gap 0.5)
			(thermal_bridge_width 0.5)
			(island_removal_mode 0)
		)
		(polygon
			(pts
				(arc
					(start 343.572846 -288.917126)
					(mid 342.914986 -288.917126)
					(end 343.572846 -288.917126)
				)
			)
		)
	)
	(zone
		(layers "F.Cu" "B.Cu" "In1.Cu" "In2.Cu" "In3.Cu" "In4.Cu" "In5.Cu" "In6.Cu"
			"In7.Cu" "In8.Cu" "In9.Cu" "In10.Cu" "In11.Cu" "In12.Cu" "In13.Cu" "In14.Cu"
			"In15.Cu" "In16.Cu"
		)
		(hatch none 0.5)
		(connect_pads
			(clearance 0)
		)
		(min_thickness 0.25)
		(keepout
			(tracks not_allowed)
			(vias allowed)
			(pads allowed)
			(copperpour not_allowed)
			(footprints allowed)
		)
		(placement
			(enabled no)
			(sheetname "")
		)
		(fill
			(thermal_gap 0.5)
			(thermal_bridge_width 0.5)
			(island_removal_mode 0)
		)
		(polygon
			(pts
				(arc
					(start 122.148092 -217.97645)
					(mid 122.167776 -217.92904)
					(end 122.174508 -217.878152)
				)
				(arc
					(start 122.174508 -217.878152)
					(mid 122.116852 -217.738958)
					(end 121.977658 -217.681302)
				)
				(arc
					(start 121.977658 -217.681302)
					(mid 121.879227 -217.707718)
					(end 121.807224 -217.779854)
				)
				(arc
					(start 121.337578 -218.593924)
					(mid 121.317894 -218.641334)
					(end 121.311162 -218.692222)
				)
				(arc
					(start 121.311162 -218.692222)
					(mid 121.368818 -218.831416)
					(end 121.508012 -218.889072)
				)
				(arc
					(start 121.508012 -218.889072)
					(mid 121.606443 -218.862656)
					(end 121.678446 -218.79052)
				)
			)
		)
	)
	(zone
		(layers "F.Cu" "B.Cu" "In1.Cu" "In2.Cu" "In3.Cu" "In4.Cu" "In5.Cu" "In6.Cu"
			"In7.Cu" "In8.Cu" "In9.Cu" "In10.Cu" "In11.Cu" "In12.Cu" "In13.Cu" "In14.Cu"
			"In15.Cu" "In16.Cu"
		)
		(hatch none 0.5)
		(connect_pads
			(clearance 0)
		)
		(min_thickness 0.25)
		(keepout
			(tracks not_allowed)
			(vias allowed)
			(pads allowed)
			(copperpour not_allowed)
			(footprints allowed)
		)
		(placement
			(enabled no)
			(sheetname "")
		)
		(fill
			(thermal_gap 0.5)
			(thermal_bridge_width 0.5)
			(island_removal_mode 0)
		)
		(polygon
			(pts
				(arc
					(start 127.786892 -214.720932)
					(mid 127.806576 -214.673522)
					(end 127.813308 -214.622634)
				)
				(arc
					(start 127.813308 -214.622634)
					(mid 127.755652 -214.48344)
					(end 127.616458 -214.425784)
				)
				(arc
					(start 127.616458 -214.425784)
					(mid 127.518027 -214.4522)
					(end 127.446024 -214.524336)
				)
				(arc
					(start 126.976378 -215.338406)
					(mid 126.956694 -215.385816)
					(end 126.949962 -215.436704)
				)
				(arc
					(start 126.949962 -215.436704)
					(mid 127.007618 -215.575898)
					(end 127.146812 -215.633554)
				)
				(arc
					(start 127.146812 -215.633554)
					(mid 127.245243 -215.607138)
					(end 127.317246 -215.535002)
				)
			)
		)
	)
	(zone
		(layers "F.Cu" "B.Cu" "In1.Cu" "In2.Cu" "In3.Cu" "In4.Cu" "In5.Cu" "In6.Cu"
			"In7.Cu" "In8.Cu" "In9.Cu" "In10.Cu" "In11.Cu" "In12.Cu" "In13.Cu" "In14.Cu"
			"In15.Cu" "In16.Cu"
		)
		(hatch none 0.5)
		(connect_pads
			(clearance 0)
		)
		(min_thickness 0.25)
		(keepout
			(tracks not_allowed)
			(vias allowed)
			(pads allowed)
			(copperpour not_allowed)
			(footprints allowed)
		)
		(placement
			(enabled no)
			(sheetname "")
		)
		(fill
			(thermal_gap 0.5)
			(thermal_bridge_width 0.5)
			(island_removal_mode 0)
		)
		(polygon
			(pts
				(arc
					(start 126.928118 -288.917126)
					(mid 127.585978 -288.917126)
					(end 126.928118 -288.917126)
				)
			)
		)
	)
	(zone
		(layers "F.Cu" "B.Cu" "In1.Cu" "In2.Cu" "In3.Cu" "In4.Cu" "In5.Cu" "In6.Cu"
			"In7.Cu" "In8.Cu" "In9.Cu" "In10.Cu" "In11.Cu" "In12.Cu" "In13.Cu" "In14.Cu"
			"In15.Cu" "In16.Cu"
		)
		(hatch none 0.5)
		(connect_pads
			(clearance 0)
		)
		(min_thickness 0.25)
		(keepout
			(tracks not_allowed)
			(vias allowed)
			(pads allowed)
			(copperpour not_allowed)
			(footprints allowed)
		)
		(placement
			(enabled no)
			(sheetname "")
		)
		(fill
			(thermal_gap 0.5)
			(thermal_bridge_width 0.5)
			(island_removal_mode 0)
		)
		(polygon
			(pts
				(arc
					(start 248.767346 5.0292)
					(mid 249.148346 4.6482)
					(end 249.529346 5.0292)
				)
				(arc
					(start 249.529346 5.8928)
					(mid 249.148346 6.2738)
					(end 248.767346 5.8928)
				)
			)
		)
	)
	(zone
		(layers "F.Cu" "B.Cu" "In1.Cu" "In2.Cu" "In3.Cu" "In4.Cu" "In5.Cu" "In6.Cu"
			"In7.Cu" "In8.Cu" "In9.Cu" "In10.Cu" "In11.Cu" "In12.Cu" "In13.Cu" "In14.Cu"
			"In15.Cu" "In16.Cu"
		)
		(hatch none 0.5)
		(connect_pads
			(clearance 0)
		)
		(min_thickness 0.25)
		(keepout
			(tracks not_allowed)
			(vias allowed)
			(pads allowed)
			(copperpour not_allowed)
			(footprints allowed)
		)
		(placement
			(enabled no)
			(sheetname "")
		)
		(fill
			(thermal_gap 0.5)
			(thermal_bridge_width 0.5)
			(island_removal_mode 0)
		)
		(polygon
			(pts
				(arc
					(start 20.821396 -4.581652)
					(mid 20.440396 -4.962652)
					(end 20.821396 -5.343652)
				)
				(arc
					(start 21.684996 -5.343652)
					(mid 22.065996 -4.962652)
					(end 21.684996 -4.581652)
				)
			)
		)
	)
	(zone
		(layers "F.Cu" "B.Cu" "In1.Cu" "In2.Cu" "In3.Cu" "In4.Cu" "In5.Cu" "In6.Cu"
			"In7.Cu" "In8.Cu" "In9.Cu" "In10.Cu" "In11.Cu" "In12.Cu" "In13.Cu" "In14.Cu"
			"In15.Cu" "In16.Cu"
		)
		(hatch none 0.5)
		(connect_pads
			(clearance 0)
		)
		(min_thickness 0.25)
		(keepout
			(tracks not_allowed)
			(vias allowed)
			(pads allowed)
			(copperpour not_allowed)
			(footprints allowed)
		)
		(placement
			(enabled no)
			(sheetname "")
		)
		(fill
			(thermal_gap 0.5)
			(thermal_bridge_width 0.5)
			(island_removal_mode 0)
		)
		(polygon
			(pts
				(arc
					(start 368.947192 -285.661354)
					(mid 368.289332 -285.661354)
					(end 368.947192 -285.661354)
				)
			)
		)
	)
	(zone
		(layers "F.Cu" "B.Cu" "In1.Cu" "In2.Cu" "In3.Cu" "In4.Cu" "In5.Cu" "In6.Cu"
			"In7.Cu" "In8.Cu" "In9.Cu" "In10.Cu" "In11.Cu" "In12.Cu" "In13.Cu" "In14.Cu"
			"In15.Cu" "In16.Cu"
		)
		(hatch none 0.5)
		(connect_pads
			(clearance 0)
		)
		(min_thickness 0.25)
		(keepout
			(tracks not_allowed)
			(vias allowed)
			(pads allowed)
			(copperpour not_allowed)
			(footprints allowed)
		)
		(placement
			(enabled no)
			(sheetname "")
		)
		(fill
			(thermal_gap 0.5)
			(thermal_bridge_width 0.5)
			(island_removal_mode 0)
		)
		(polygon
			(pts
				(arc
					(start 132.566664 -285.661354)
					(mid 133.224524 -285.661354)
					(end 132.566664 -285.661354)
				)
			)
		)
	)
	(zone
		(layers "F.Cu" "B.Cu" "In1.Cu" "In2.Cu" "In3.Cu" "In4.Cu" "In5.Cu" "In6.Cu"
			"In7.Cu" "In8.Cu" "In9.Cu" "In10.Cu" "In11.Cu" "In12.Cu" "In13.Cu" "In14.Cu"
			"In15.Cu" "In16.Cu"
		)
		(hatch none 0.5)
		(connect_pads
			(clearance 0)
		)
		(min_thickness 0.25)
		(keepout
			(tracks not_allowed)
			(vias allowed)
			(pads allowed)
			(copperpour not_allowed)
			(footprints allowed)
		)
		(placement
			(enabled no)
			(sheetname "")
		)
		(fill
			(thermal_gap 0.5)
			(thermal_bridge_width 0.5)
			(island_removal_mode 0)
		)
		(polygon
			(pts
				(arc
					(start 108.132118 -275.8948)
					(mid 108.789978 -275.8948)
					(end 108.132118 -275.8948)
				)
			)
		)
	)
	(zone
		(layers "F.Cu" "B.Cu" "In1.Cu" "In2.Cu" "In3.Cu" "In4.Cu" "In5.Cu" "In6.Cu"
			"In7.Cu" "In8.Cu" "In9.Cu" "In10.Cu" "In11.Cu" "In12.Cu" "In13.Cu" "In14.Cu"
			"In15.Cu" "In16.Cu"
		)
		(hatch none 0.5)
		(connect_pads
			(clearance 0)
		)
		(min_thickness 0.25)
		(keepout
			(tracks not_allowed)
			(vias allowed)
			(pads allowed)
			(copperpour not_allowed)
			(footprints allowed)
		)
		(placement
			(enabled no)
			(sheetname "")
		)
		(fill
			(thermal_gap 0.5)
			(thermal_bridge_width 0.5)
			(island_removal_mode 0)
		)
		(polygon
			(pts
				(arc
					(start 349.875348 -213.646766)
					(mid 349.80764 -213.574915)
					(end 349.712534 -213.548468)
				)
				(arc
					(start 349.712534 -213.548468)
					(mid 349.58232 -213.602404)
					(end 349.528384 -213.732618)
				)
				(arc
					(start 349.528384 -213.732618)
					(mid 349.533835 -213.776839)
					(end 349.54972 -213.81847)
				)
				(arc
					(start 350.019112 -214.708486)
					(mid 350.08682 -214.780337)
					(end 350.181926 -214.806784)
				)
				(arc
					(start 350.181926 -214.806784)
					(mid 350.31214 -214.752848)
					(end 350.366076 -214.622634)
				)
				(arc
					(start 350.366076 -214.622634)
					(mid 350.360625 -214.578413)
					(end 350.34474 -214.536782)
				)
			)
		)
	)
	(zone
		(layers "F.Cu" "B.Cu" "In1.Cu" "In2.Cu" "In3.Cu" "In4.Cu" "In5.Cu" "In6.Cu"
			"In7.Cu" "In8.Cu" "In9.Cu" "In10.Cu" "In11.Cu" "In12.Cu" "In13.Cu" "In14.Cu"
			"In15.Cu" "In16.Cu"
		)
		(hatch none 0.5)
		(connect_pads
			(clearance 0)
		)
		(min_thickness 0.25)
		(keepout
			(tracks not_allowed)
			(vias allowed)
			(pads allowed)
			(copperpour not_allowed)
			(footprints allowed)
		)
		(placement
			(enabled no)
			(sheetname "")
		)
		(fill
			(thermal_gap 0.5)
			(thermal_bridge_width 0.5)
			(island_removal_mode 0)
		)
		(polygon
			(pts
				(arc
					(start 350.352868 -224.291144)
					(mid 350.280879 -224.218985)
					(end 350.182434 -224.192592)
				)
				(arc
					(start 350.182434 -224.192592)
					(mid 350.04324 -224.250248)
					(end 349.985584 -224.389442)
				)
				(arc
					(start 349.985584 -224.389442)
					(mid 349.992341 -224.440323)
					(end 350.012 -224.48774)
				)
				(arc
					(start 350.481646 -225.301556)
					(mid 350.553635 -225.373715)
					(end 350.65208 -225.400108)
				)
				(arc
					(start 350.65208 -225.400108)
					(mid 350.791274 -225.342452)
					(end 350.84893 -225.203258)
				)
				(arc
					(start 350.84893 -225.203258)
					(mid 350.842173 -225.152377)
					(end 350.822514 -225.10496)
				)
			)
		)
	)
	(zone
		(layers "F.Cu" "B.Cu" "In1.Cu" "In2.Cu" "In3.Cu" "In4.Cu" "In5.Cu" "In6.Cu"
			"In7.Cu" "In8.Cu" "In9.Cu" "In10.Cu" "In11.Cu" "In12.Cu" "In13.Cu" "In14.Cu"
			"In15.Cu" "In16.Cu"
		)
		(hatch none 0.5)
		(connect_pads
			(clearance 0)
		)
		(min_thickness 0.25)
		(keepout
			(tracks not_allowed)
			(vias allowed)
			(pads allowed)
			(copperpour not_allowed)
			(footprints allowed)
		)
		(placement
			(enabled no)
			(sheetname "")
		)
		(fill
			(thermal_gap 0.5)
			(thermal_bridge_width 0.5)
			(island_removal_mode 0)
		)
		(polygon
			(pts
				(arc
					(start 300.57344 -162.702748)
					(mid 300.19244 -163.083748)
					(end 300.57344 -163.464748)
				)
				(arc
					(start 301.43704 -163.464748)
					(mid 301.81804 -163.083748)
					(end 301.43704 -162.702748)
				)
			)
		)
	)
	(zone
		(layers "F.Cu" "B.Cu" "In1.Cu" "In2.Cu" "In3.Cu" "In4.Cu" "In5.Cu" "In6.Cu"
			"In7.Cu" "In8.Cu" "In9.Cu" "In10.Cu" "In11.Cu" "In12.Cu" "In13.Cu" "In14.Cu"
			"In15.Cu" "In16.Cu"
		)
		(hatch none 0.5)
		(connect_pads
			(clearance 0)
		)
		(min_thickness 0.25)
		(keepout
			(tracks not_allowed)
			(vias allowed)
			(pads allowed)
			(copperpour not_allowed)
			(footprints allowed)
		)
		(placement
			(enabled no)
			(sheetname "")
		)
		(fill
			(thermal_gap 0.5)
			(thermal_bridge_width 0.5)
			(island_removal_mode 0)
		)
		(polygon
			(pts
				(arc
					(start 132.407914 -403.502876)
					(mid 132.026914 -403.883876)
					(end 132.407914 -404.264876)
				)
				(arc
					(start 133.271514 -404.264876)
					(mid 133.652514 -403.883876)
					(end 133.271514 -403.502876)
				)
			)
		)
	)
	(zone
		(layers "F.Cu" "B.Cu" "In1.Cu" "In2.Cu" "In3.Cu" "In4.Cu" "In5.Cu" "In6.Cu"
			"In7.Cu" "In8.Cu" "In9.Cu" "In10.Cu" "In11.Cu" "In12.Cu" "In13.Cu" "In14.Cu"
			"In15.Cu" "In16.Cu"
		)
		(hatch none 0.5)
		(connect_pads
			(clearance 0)
		)
		(min_thickness 0.25)
		(keepout
			(tracks not_allowed)
			(vias allowed)
			(pads allowed)
			(copperpour not_allowed)
			(footprints allowed)
		)
		(placement
			(enabled no)
			(sheetname "")
		)
		(fill
			(thermal_gap 0.5)
			(thermal_bridge_width 0.5)
			(island_removal_mode 0)
		)
		(polygon
			(pts
				(arc
					(start 132.566918 -288.917126)
					(mid 133.224778 -288.917126)
					(end 132.566918 -288.917126)
				)
			)
		)
	)
	(zone
		(layers "F.Cu" "B.Cu" "In1.Cu" "In2.Cu" "In3.Cu" "In4.Cu" "In5.Cu" "In6.Cu"
			"In7.Cu" "In8.Cu" "In9.Cu" "In10.Cu" "In11.Cu" "In12.Cu" "In13.Cu" "In14.Cu"
			"In15.Cu" "In16.Cu"
		)
		(hatch none 0.5)
		(connect_pads
			(clearance 0)
		)
		(min_thickness 0.25)
		(keepout
			(tracks not_allowed)
			(vias allowed)
			(pads allowed)
			(copperpour not_allowed)
			(footprints allowed)
		)
		(placement
			(enabled no)
			(sheetname "")
		)
		(fill
			(thermal_gap 0.5)
			(thermal_bridge_width 0.5)
			(island_removal_mode 0)
		)
		(polygon
			(pts
				(arc
					(start 418.2872 -17.220438)
					(mid 417.9062 -17.601438)
					(end 418.2872 -17.982438)
				)
				(arc
					(start 419.1508 -17.982438)
					(mid 419.5318 -17.601438)
					(end 419.1508 -17.220438)
				)
			)
		)
	)
	(zone
		(layers "F.Cu" "B.Cu" "In1.Cu" "In2.Cu" "In3.Cu" "In4.Cu" "In5.Cu" "In6.Cu"
			"In7.Cu" "In8.Cu" "In9.Cu" "In10.Cu" "In11.Cu" "In12.Cu" "In13.Cu" "In14.Cu"
			"In15.Cu" "In16.Cu"
		)
		(hatch none 0.5)
		(connect_pads
			(clearance 0)
		)
		(min_thickness 0.25)
		(keepout
			(tracks not_allowed)
			(vias allowed)
			(pads allowed)
			(copperpour not_allowed)
			(footprints allowed)
		)
		(placement
			(enabled no)
			(sheetname "")
		)
		(fill
			(thermal_gap 0.5)
			(thermal_bridge_width 0.5)
			(island_removal_mode 0)
		)
		(polygon
			(pts
				(arc
					(start 240.2205 -49.400206)
					(mid 239.8395 -49.019206)
					(end 239.4585 -49.400206)
				)
				(arc
					(start 239.4585 -50.263806)
					(mid 239.8395 -50.644806)
					(end 240.2205 -50.263806)
				)
			)
		)
	)
	(zone
		(layers "F.Cu" "B.Cu" "In1.Cu" "In2.Cu" "In3.Cu" "In4.Cu" "In5.Cu" "In6.Cu"
			"In7.Cu" "In8.Cu" "In9.Cu" "In10.Cu" "In11.Cu" "In12.Cu" "In13.Cu" "In14.Cu"
			"In15.Cu" "In16.Cu"
		)
		(hatch none 0.5)
		(connect_pads
			(clearance 0)
		)
		(min_thickness 0.25)
		(keepout
			(tracks not_allowed)
			(vias allowed)
			(pads allowed)
			(copperpour not_allowed)
			(footprints allowed)
		)
		(placement
			(enabled no)
			(sheetname "")
		)
		(fill
			(thermal_gap 0.5)
			(thermal_bridge_width 0.5)
			(island_removal_mode 0)
		)
		(polygon
			(pts
				(arc
					(start 350.04121 -217.064336)
					(mid 349.38335 -217.064336)
					(end 350.04121 -217.064336)
				)
			)
		)
	)
	(zone
		(layers "F.Cu" "B.Cu" "In1.Cu" "In2.Cu" "In3.Cu" "In4.Cu" "In5.Cu" "In6.Cu"
			"In7.Cu" "In8.Cu" "In9.Cu" "In10.Cu" "In11.Cu" "In12.Cu" "In13.Cu" "In14.Cu"
			"In15.Cu" "In16.Cu"
		)
		(hatch none 0.5)
		(connect_pads
			(clearance 0)
		)
		(min_thickness 0.25)
		(keepout
			(tracks not_allowed)
			(vias allowed)
			(pads allowed)
			(copperpour not_allowed)
			(footprints allowed)
		)
		(placement
			(enabled no)
			(sheetname "")
		)
		(fill
			(thermal_gap 0.5)
			(thermal_bridge_width 0.5)
			(island_removal_mode 0)
		)
		(polygon
			(pts
				(arc
					(start 75.548998 -400.477228)
					(mid 75.167998 -400.858228)
					(end 75.548998 -401.239228)
				)
				(arc
					(start 76.412598 -401.239228)
					(mid 76.793598 -400.858228)
					(end 76.412598 -400.477228)
				)
			)
		)
	)
	(zone
		(layers "F.Cu" "B.Cu" "In1.Cu" "In2.Cu" "In3.Cu" "In4.Cu" "In5.Cu" "In6.Cu"
			"In7.Cu" "In8.Cu" "In9.Cu" "In10.Cu" "In11.Cu" "In12.Cu" "In13.Cu" "In14.Cu"
			"In15.Cu" "In16.Cu"
		)
		(hatch none 0.5)
		(connect_pads
			(clearance 0)
		)
		(min_thickness 0.25)
		(keepout
			(tracks not_allowed)
			(vias allowed)
			(pads allowed)
			(copperpour not_allowed)
			(footprints allowed)
		)
		(placement
			(enabled no)
			(sheetname "")
		)
		(fill
			(thermal_gap 0.5)
			(thermal_bridge_width 0.5)
			(island_removal_mode 0)
		)
		(polygon
			(pts
				(arc
					(start 158.260034 -406.62352)
					(mid 157.879034 -407.00452)
					(end 158.260034 -407.38552)
				)
				(arc
					(start 159.123634 -407.38552)
					(mid 159.504634 -407.00452)
					(end 159.123634 -406.62352)
				)
			)
		)
	)
	(zone
		(layers "F.Cu" "B.Cu" "In1.Cu" "In2.Cu" "In3.Cu" "In4.Cu" "In5.Cu" "In6.Cu"
			"In7.Cu" "In8.Cu" "In9.Cu" "In10.Cu" "In11.Cu" "In12.Cu" "In13.Cu" "In14.Cu"
			"In15.Cu" "In16.Cu"
		)
		(hatch none 0.5)
		(connect_pads
			(clearance 0)
		)
		(min_thickness 0.25)
		(keepout
			(tracks not_allowed)
			(vias allowed)
			(pads allowed)
			(copperpour not_allowed)
			(footprints allowed)
		)
		(placement
			(enabled no)
			(sheetname "")
		)
		(fill
			(thermal_gap 0.5)
			(thermal_bridge_width 0.5)
			(island_removal_mode 0)
		)
		(polygon
			(pts
				(arc
					(start 353.641914 -223.67367)
					(mid 353.661598 -223.62626)
					(end 353.66833 -223.575372)
				)
				(arc
					(start 353.66833 -223.575372)
					(mid 353.610674 -223.436178)
					(end 353.47148 -223.378522)
				)
				(arc
					(start 353.47148 -223.378522)
					(mid 353.373049 -223.404938)
					(end 353.301046 -223.477074)
				)
				(arc
					(start 352.8314 -224.291144)
					(mid 352.811716 -224.338554)
					(end 352.804984 -224.389442)
				)
				(arc
					(start 352.804984 -224.389442)
					(mid 352.86264 -224.528636)
					(end 353.001834 -224.586292)
				)
				(arc
					(start 353.001834 -224.586292)
					(mid 353.100265 -224.559876)
					(end 353.172268 -224.48774)
				)
			)
		)
	)
	(zone
		(layers "F.Cu" "B.Cu" "In1.Cu" "In2.Cu" "In3.Cu" "In4.Cu" "In5.Cu" "In6.Cu"
			"In7.Cu" "In8.Cu" "In9.Cu" "In10.Cu" "In11.Cu" "In12.Cu" "In13.Cu" "In14.Cu"
			"In15.Cu" "In16.Cu"
		)
		(hatch none 0.5)
		(connect_pads
			(clearance 0)
		)
		(min_thickness 0.25)
		(keepout
			(tracks not_allowed)
			(vias allowed)
			(pads allowed)
			(copperpour not_allowed)
			(footprints allowed)
		)
		(placement
			(enabled no)
			(sheetname "")
		)
		(fill
			(thermal_gap 0.5)
			(thermal_bridge_width 0.5)
			(island_removal_mode 0)
		)
		(polygon
			(pts
				(arc
					(start 95.052388 -214.622634)
					(mid 94.394528 -214.622634)
					(end 95.052388 -214.622634)
				)
			)
		)
	)
	(zone
		(layers "F.Cu" "B.Cu" "In1.Cu" "In2.Cu" "In3.Cu" "In4.Cu" "In5.Cu" "In6.Cu"
			"In7.Cu" "In8.Cu" "In9.Cu" "In10.Cu" "In11.Cu" "In12.Cu" "In13.Cu" "In14.Cu"
			"In15.Cu" "In16.Cu"
		)
		(hatch none 0.5)
		(connect_pads
			(clearance 0)
		)
		(min_thickness 0.25)
		(keepout
			(tracks not_allowed)
			(vias allowed)
			(pads allowed)
			(copperpour not_allowed)
			(footprints allowed)
		)
		(placement
			(enabled no)
			(sheetname "")
		)
		(fill
			(thermal_gap 0.5)
			(thermal_bridge_width 0.5)
			(island_removal_mode 0)
		)
		(polygon
			(pts
				(arc
					(start 100.613464 -280.778204)
					(mid 101.271324 -280.778204)
					(end 100.613464 -280.778204)
				)
			)
		)
	)
	(zone
		(layers "F.Cu" "B.Cu" "In1.Cu" "In2.Cu" "In3.Cu" "In4.Cu" "In5.Cu" "In6.Cu"
			"In7.Cu" "In8.Cu" "In9.Cu" "In10.Cu" "In11.Cu" "In12.Cu" "In13.Cu" "In14.Cu"
			"In15.Cu" "In16.Cu"
		)
		(hatch none 0.5)
		(connect_pads
			(clearance 0)
		)
		(min_thickness 0.25)
		(keepout
			(tracks not_allowed)
			(vias allowed)
			(pads allowed)
			(copperpour not_allowed)
			(footprints allowed)
		)
		(placement
			(enabled no)
			(sheetname "")
		)
		(fill
			(thermal_gap 0.5)
			(thermal_bridge_width 0.5)
			(island_removal_mode 0)
		)
		(polygon
			(pts
				(arc
					(start 166.735506 -11.624056)
					(mid 166.354506 -12.005056)
					(end 166.735506 -12.386056)
				)
				(arc
					(start 167.599106 -12.386056)
					(mid 167.980106 -12.005056)
					(end 167.599106 -11.624056)
				)
			)
		)
	)
	(zone
		(layers "F.Cu" "B.Cu" "In1.Cu" "In2.Cu" "In3.Cu" "In4.Cu" "In5.Cu" "In6.Cu"
			"In7.Cu" "In8.Cu" "In9.Cu" "In10.Cu" "In11.Cu" "In12.Cu" "In13.Cu" "In14.Cu"
			"In15.Cu" "In16.Cu"
		)
		(hatch none 0.5)
		(connect_pads
			(clearance 0)
		)
		(min_thickness 0.25)
		(keepout
			(tracks not_allowed)
			(vias allowed)
			(pads allowed)
			(copperpour not_allowed)
			(footprints allowed)
		)
		(placement
			(enabled no)
			(sheetname "")
		)
		(fill
			(thermal_gap 0.5)
			(thermal_bridge_width 0.5)
			(island_removal_mode 0)
		)
		(polygon
			(pts
				(arc
					(start 378.345446 -288.917126)
					(mid 377.687586 -288.917126)
					(end 378.345446 -288.917126)
				)
			)
		)
	)
	(zone
		(layers "F.Cu" "B.Cu" "In1.Cu" "In2.Cu" "In3.Cu" "In4.Cu" "In5.Cu" "In6.Cu"
			"In7.Cu" "In8.Cu" "In9.Cu" "In10.Cu" "In11.Cu" "In12.Cu" "In13.Cu" "In14.Cu"
			"In15.Cu" "In16.Cu"
		)
		(hatch none 0.5)
		(connect_pads
			(clearance 0)
		)
		(min_thickness 0.25)
		(keepout
			(tracks not_allowed)
			(vias allowed)
			(pads allowed)
			(copperpour not_allowed)
			(footprints allowed)
		)
		(placement
			(enabled no)
			(sheetname "")
		)
		(fill
			(thermal_gap 0.5)
			(thermal_bridge_width 0.5)
			(island_removal_mode 0)
		)
		(polygon
			(pts
				(arc
					(start 101.71176 -285.563056)
					(mid 101.692076 -285.610466)
					(end 101.685344 -285.661354)
				)
				(arc
					(start 101.685344 -285.661354)
					(mid 101.743 -285.800548)
					(end 101.882194 -285.858204)
				)
				(arc
					(start 101.882194 -285.858204)
					(mid 101.980625 -285.831788)
					(end 102.052628 -285.759652)
				)
				(arc
					(start 102.522528 -284.945582)
					(mid 102.542212 -284.898172)
					(end 102.548944 -284.847284)
				)
				(arc
					(start 102.548944 -284.847284)
					(mid 102.491288 -284.70809)
					(end 102.352094 -284.650434)
				)
				(arc
					(start 102.352094 -284.650434)
					(mid 102.253663 -284.67685)
					(end 102.18166 -284.748986)
				)
			)
		)
	)
	(zone
		(layers "F.Cu" "B.Cu" "In1.Cu" "In2.Cu" "In3.Cu" "In4.Cu" "In5.Cu" "In6.Cu"
			"In7.Cu" "In8.Cu" "In9.Cu" "In10.Cu" "In11.Cu" "In12.Cu" "In13.Cu" "In14.Cu"
			"In15.Cu" "In16.Cu"
		)
		(hatch none 0.5)
		(connect_pads
			(clearance 0)
		)
		(min_thickness 0.25)
		(keepout
			(tracks not_allowed)
			(vias allowed)
			(pads allowed)
			(copperpour not_allowed)
			(footprints allowed)
		)
		(placement
			(enabled no)
			(sheetname "")
		)
		(fill
			(thermal_gap 0.5)
			(thermal_bridge_width 0.5)
			(island_removal_mode 0)
		)
		(polygon
			(pts
				(arc
					(start 132.016754 -216.966292)
					(mid 131.944765 -216.894133)
					(end 131.84632 -216.86774)
				)
				(arc
					(start 131.84632 -216.86774)
					(mid 131.707126 -216.925396)
					(end 131.64947 -217.06459)
				)
				(arc
					(start 131.64947 -217.06459)
					(mid 131.656227 -217.115471)
					(end 131.675886 -217.162888)
				)
				(arc
					(start 132.145532 -217.976704)
					(mid 132.217521 -218.048863)
					(end 132.315966 -218.075256)
				)
				(arc
					(start 132.315966 -218.075256)
					(mid 132.45516 -218.0176)
					(end 132.512816 -217.878406)
				)
				(arc
					(start 132.512816 -217.878406)
					(mid 132.506059 -217.827525)
					(end 132.4864 -217.780108)
				)
			)
		)
	)
	(zone
		(layers "F.Cu" "B.Cu" "In1.Cu" "In2.Cu" "In3.Cu" "In4.Cu" "In5.Cu" "In6.Cu"
			"In7.Cu" "In8.Cu" "In9.Cu" "In10.Cu" "In11.Cu" "In12.Cu" "In13.Cu" "In14.Cu"
			"In15.Cu" "In16.Cu"
		)
		(hatch none 0.5)
		(connect_pads
			(clearance 0)
		)
		(min_thickness 0.25)
		(keepout
			(tracks not_allowed)
			(vias allowed)
			(pads allowed)
			(copperpour not_allowed)
			(footprints allowed)
		)
		(placement
			(enabled no)
			(sheetname "")
		)
		(fill
			(thermal_gap 0.5)
			(thermal_bridge_width 0.5)
			(island_removal_mode 0)
		)
		(polygon
			(pts
				(arc
					(start 367.269268 -224.291144)
					(mid 367.197279 -224.218985)
					(end 367.098834 -224.192592)
				)
				(arc
					(start 367.098834 -224.192592)
					(mid 366.95964 -224.250248)
					(end 366.901984 -224.389442)
				)
				(arc
					(start 366.901984 -224.389442)
					(mid 366.908741 -224.440323)
					(end 366.9284 -224.48774)
				)
				(arc
					(start 367.398046 -225.301556)
					(mid 367.470035 -225.373715)
					(end 367.56848 -225.400108)
				)
				(arc
					(start 367.56848 -225.400108)
					(mid 367.707674 -225.342452)
					(end 367.76533 -225.203258)
				)
				(arc
					(start 367.76533 -225.203258)
					(mid 367.758573 -225.152377)
					(end 367.738914 -225.10496)
				)
			)
		)
	)
	(zone
		(layers "F.Cu" "B.Cu" "In1.Cu" "In2.Cu" "In3.Cu" "In4.Cu" "In5.Cu" "In6.Cu"
			"In7.Cu" "In8.Cu" "In9.Cu" "In10.Cu" "In11.Cu" "In12.Cu" "In13.Cu" "In14.Cu"
			"In15.Cu" "In16.Cu"
		)
		(hatch none 0.5)
		(connect_pads
			(clearance 0)
		)
		(min_thickness 0.25)
		(keepout
			(tracks not_allowed)
			(vias allowed)
			(pads allowed)
			(copperpour not_allowed)
			(footprints allowed)
		)
		(placement
			(enabled no)
			(sheetname "")
		)
		(fill
			(thermal_gap 0.5)
			(thermal_bridge_width 0.5)
			(island_removal_mode 0)
		)
		(polygon
			(pts
				(arc
					(start 130.6068 -224.291144)
					(mid 130.534811 -224.218985)
					(end 130.436366 -224.192592)
				)
				(arc
					(start 130.436366 -224.192592)
					(mid 130.297172 -224.250248)
					(end 130.239516 -224.389442)
				)
				(arc
					(start 130.239516 -224.389442)
					(mid 130.246273 -224.440323)
					(end 130.265932 -224.48774)
				)
				(arc
					(start 130.735578 -225.301556)
					(mid 130.807567 -225.373715)
					(end 130.906012 -225.400108)
				)
				(arc
					(start 130.906012 -225.400108)
					(mid 131.045206 -225.342452)
					(end 131.102862 -225.203258)
				)
				(arc
					(start 131.102862 -225.203258)
					(mid 131.096105 -225.152377)
					(end 131.076446 -225.10496)
				)
			)
		)
	)
	(zone
		(layers "F.Cu" "B.Cu" "In1.Cu" "In2.Cu" "In3.Cu" "In4.Cu" "In5.Cu" "In6.Cu"
			"In7.Cu" "In8.Cu" "In9.Cu" "In10.Cu" "In11.Cu" "In12.Cu" "In13.Cu" "In14.Cu"
			"In15.Cu" "In16.Cu"
		)
		(hatch none 0.5)
		(connect_pads
			(clearance 0)
		)
		(min_thickness 0.25)
		(keepout
			(tracks not_allowed)
			(vias allowed)
			(pads allowed)
			(copperpour not_allowed)
			(footprints allowed)
		)
		(placement
			(enabled no)
			(sheetname "")
		)
		(fill
			(thermal_gap 0.5)
			(thermal_bridge_width 0.5)
			(island_removal_mode 0)
		)
		(polygon
			(pts
				(arc
					(start 90.194892 -214.720932)
					(mid 90.214576 -214.673522)
					(end 90.221308 -214.622634)
				)
				(arc
					(start 90.221308 -214.622634)
					(mid 90.163652 -214.48344)
					(end 90.024458 -214.425784)
				)
				(arc
					(start 90.024458 -214.425784)
					(mid 89.926027 -214.4522)
					(end 89.854024 -214.524336)
				)
				(arc
					(start 89.384378 -215.338406)
					(mid 89.364694 -215.385816)
					(end 89.357962 -215.436704)
				)
				(arc
					(start 89.357962 -215.436704)
					(mid 89.415618 -215.575898)
					(end 89.554812 -215.633554)
				)
				(arc
					(start 89.554812 -215.633554)
					(mid 89.653243 -215.607138)
					(end 89.725246 -215.535002)
				)
			)
		)
	)
	(zone
		(layers "F.Cu" "B.Cu" "In1.Cu" "In2.Cu" "In3.Cu" "In4.Cu" "In5.Cu" "In6.Cu"
			"In7.Cu" "In8.Cu" "In9.Cu" "In10.Cu" "In11.Cu" "In12.Cu" "In13.Cu" "In14.Cu"
			"In15.Cu" "In16.Cu"
		)
		(hatch none 0.5)
		(connect_pads
			(clearance 0)
		)
		(min_thickness 0.25)
		(keepout
			(tracks not_allowed)
			(vias allowed)
			(pads allowed)
			(copperpour not_allowed)
			(footprints allowed)
		)
		(placement
			(enabled no)
			(sheetname "")
		)
		(fill
			(thermal_gap 0.5)
			(thermal_bridge_width 0.5)
			(island_removal_mode 0)
		)
		(polygon
			(pts
				(arc
					(start 341.113364 -221.133924)
					(mid 340.455504 -221.133924)
					(end 341.113364 -221.133924)
				)
			)
		)
	)
	(zone
		(layers "F.Cu" "B.Cu" "In1.Cu" "In2.Cu" "In3.Cu" "In4.Cu" "In5.Cu" "In6.Cu"
			"In7.Cu" "In8.Cu" "In9.Cu" "In10.Cu" "In11.Cu" "In12.Cu" "In13.Cu" "In14.Cu"
			"In15.Cu" "In16.Cu"
		)
		(hatch none 0.5)
		(connect_pads
			(clearance 0)
		)
		(min_thickness 0.25)
		(keepout
			(tracks not_allowed)
			(vias allowed)
			(pads allowed)
			(copperpour not_allowed)
			(footprints allowed)
		)
		(placement
			(enabled no)
			(sheetname "")
		)
		(fill
			(thermal_gap 0.5)
			(thermal_bridge_width 0.5)
			(island_removal_mode 0)
		)
		(polygon
			(pts
				(arc
					(start 104.842818 -276.708616)
					(mid 105.500678 -276.708616)
					(end 104.842818 -276.708616)
				)
			)
		)
	)
	(zone
		(layers "F.Cu" "B.Cu" "In1.Cu" "In2.Cu" "In3.Cu" "In4.Cu" "In5.Cu" "In6.Cu"
			"In7.Cu" "In8.Cu" "In9.Cu" "In10.Cu" "In11.Cu" "In12.Cu" "In13.Cu" "In14.Cu"
			"In15.Cu" "In16.Cu"
		)
		(hatch none 0.5)
		(connect_pads
			(clearance 0)
		)
		(min_thickness 0.25)
		(keepout
			(tracks not_allowed)
			(vias allowed)
			(pads allowed)
			(copperpour not_allowed)
			(footprints allowed)
		)
		(placement
			(enabled no)
			(sheetname "")
		)
		(fill
			(thermal_gap 0.5)
			(thermal_bridge_width 0.5)
			(island_removal_mode 0)
		)
		(polygon
			(pts
				(arc
					(start 349.928688 -400.477228)
					(mid 349.547688 -400.858228)
					(end 349.928688 -401.239228)
				)
				(arc
					(start 350.792288 -401.239228)
					(mid 351.173288 -400.858228)
					(end 350.792288 -400.477228)
				)
			)
		)
	)
	(zone
		(layers "F.Cu" "B.Cu" "In1.Cu" "In2.Cu" "In3.Cu" "In4.Cu" "In5.Cu" "In6.Cu"
			"In7.Cu" "In8.Cu" "In9.Cu" "In10.Cu" "In11.Cu" "In12.Cu" "In13.Cu" "In14.Cu"
			"In15.Cu" "In16.Cu"
		)
		(hatch none 0.5)
		(connect_pads
			(clearance 0)
		)
		(min_thickness 0.25)
		(keepout
			(tracks not_allowed)
			(vias allowed)
			(pads allowed)
			(copperpour not_allowed)
			(footprints allowed)
		)
		(placement
			(enabled no)
			(sheetname "")
		)
		(fill
			(thermal_gap 0.5)
			(thermal_bridge_width 0.5)
			(island_removal_mode 0)
		)
		(polygon
			(pts
				(arc
					(start 124.938282 -215.436704)
					(mid 125.596142 -215.436704)
					(end 124.938282 -215.436704)
				)
			)
		)
	)
	(zone
		(layers "F.Cu" "B.Cu" "In1.Cu" "In2.Cu" "In3.Cu" "In4.Cu" "In5.Cu" "In6.Cu"
			"In7.Cu" "In8.Cu" "In9.Cu" "In10.Cu" "In11.Cu" "In12.Cu" "In13.Cu" "In14.Cu"
			"In15.Cu" "In16.Cu"
		)
		(hatch none 0.5)
		(connect_pads
			(clearance 0)
		)
		(min_thickness 0.25)
		(keepout
			(tracks not_allowed)
			(vias allowed)
			(pads allowed)
			(copperpour not_allowed)
			(footprints allowed)
		)
		(placement
			(enabled no)
			(sheetname "")
		)
		(fill
			(thermal_gap 0.5)
			(thermal_bridge_width 0.5)
			(island_removal_mode 0)
		)
		(polygon
			(pts
				(arc
					(start 346.752164 -217.878406)
					(mid 346.094304 -217.878406)
					(end 346.752164 -217.878406)
				)
			)
		)
	)
	(zone
		(layers "F.Cu" "B.Cu" "In1.Cu" "In2.Cu" "In3.Cu" "In4.Cu" "In5.Cu" "In6.Cu"
			"In7.Cu" "In8.Cu" "In9.Cu" "In10.Cu" "In11.Cu" "In12.Cu" "In13.Cu" "In14.Cu"
			"In15.Cu" "In16.Cu"
		)
		(hatch none 0.5)
		(connect_pads
			(clearance 0)
		)
		(min_thickness 0.25)
		(keepout
			(tracks not_allowed)
			(vias allowed)
			(pads allowed)
			(copperpour not_allowed)
			(footprints allowed)
		)
		(placement
			(enabled no)
			(sheetname "")
		)
		(fill
			(thermal_gap 0.5)
			(thermal_bridge_width 0.5)
			(island_removal_mode 0)
		)
		(polygon
			(pts
				(arc
					(start 159.16656 -47.562008)
					(mid 158.78556 -47.943008)
					(end 159.16656 -48.324008)
				)
				(arc
					(start 160.03016 -48.324008)
					(mid 160.41116 -47.943008)
					(end 160.03016 -47.562008)
				)
			)
		)
	)
	(zone
		(layers "F.Cu" "B.Cu" "In1.Cu" "In2.Cu" "In3.Cu" "In4.Cu" "In5.Cu" "In6.Cu"
			"In7.Cu" "In8.Cu" "In9.Cu" "In10.Cu" "In11.Cu" "In12.Cu" "In13.Cu" "In14.Cu"
			"In15.Cu" "In16.Cu"
		)
		(hatch none 0.5)
		(connect_pads
			(clearance 0)
		)
		(min_thickness 0.25)
		(keepout
			(tracks not_allowed)
			(vias allowed)
			(pads allowed)
			(copperpour not_allowed)
			(footprints allowed)
		)
		(placement
			(enabled no)
			(sheetname "")
		)
		(fill
			(thermal_gap 0.5)
			(thermal_bridge_width 0.5)
			(island_removal_mode 0)
		)
		(polygon
			(pts
				(arc
					(start 127.786892 -221.231968)
					(mid 127.806576 -221.184558)
					(end 127.813308 -221.13367)
				)
				(arc
					(start 127.813308 -221.13367)
					(mid 127.755652 -220.994476)
					(end 127.616458 -220.93682)
				)
				(arc
					(start 127.616458 -220.93682)
					(mid 127.518027 -220.963236)
					(end 127.446024 -221.035372)
				)
				(arc
					(start 126.976378 -221.849442)
					(mid 126.956694 -221.896852)
					(end 126.949962 -221.94774)
				)
				(arc
					(start 126.949962 -221.94774)
					(mid 127.007618 -222.086934)
					(end 127.146812 -222.14459)
				)
				(arc
					(start 127.146812 -222.14459)
					(mid 127.245243 -222.118174)
					(end 127.317246 -222.046038)
				)
			)
		)
	)
	(zone
		(layers "F.Cu" "B.Cu" "In1.Cu" "In2.Cu" "In3.Cu" "In4.Cu" "In5.Cu" "In6.Cu"
			"In7.Cu" "In8.Cu" "In9.Cu" "In10.Cu" "In11.Cu" "In12.Cu" "In13.Cu" "In14.Cu"
			"In15.Cu" "In16.Cu"
		)
		(hatch none 0.5)
		(connect_pads
			(clearance 0)
		)
		(min_thickness 0.25)
		(keepout
			(tracks not_allowed)
			(vias allowed)
			(pads allowed)
			(copperpour not_allowed)
			(footprints allowed)
		)
		(placement
			(enabled no)
			(sheetname "")
		)
		(fill
			(thermal_gap 0.5)
			(thermal_bridge_width 0.5)
			(island_removal_mode 0)
		)
		(polygon
			(pts
				(xy 470.499948 -200.144126) (xy 470.499948 -195.144136) (xy 470.804748 -195.448936) (xy 470.804748 -199.839326)
			)
		)
	)
	(zone
		(layers "F.Cu" "B.Cu" "In1.Cu" "In2.Cu" "In3.Cu" "In4.Cu" "In5.Cu" "In6.Cu"
			"In7.Cu" "In8.Cu" "In9.Cu" "In10.Cu" "In11.Cu" "In12.Cu" "In13.Cu" "In14.Cu"
			"In15.Cu" "In16.Cu"
		)
		(hatch none 0.5)
		(connect_pads
			(clearance 0)
		)
		(min_thickness 0.25)
		(keepout
			(tracks not_allowed)
			(vias allowed)
			(pads allowed)
			(copperpour not_allowed)
			(footprints allowed)
		)
		(placement
			(enabled no)
			(sheetname "")
		)
		(fill
			(thermal_gap 0.5)
			(thermal_bridge_width 0.5)
			(island_removal_mode 0)
		)
		(polygon
			(pts
				(arc
					(start 350.672908 -49.826672)
					(mid 350.291908 -50.207672)
					(end 350.672908 -50.588672)
				)
				(arc
					(start 351.536508 -50.588672)
					(mid 351.917508 -50.207672)
					(end 351.536508 -49.826672)
				)
			)
		)
	)
	(zone
		(layers "F.Cu" "B.Cu" "In1.Cu" "In2.Cu" "In3.Cu" "In4.Cu" "In5.Cu" "In6.Cu"
			"In7.Cu" "In8.Cu" "In9.Cu" "In10.Cu" "In11.Cu" "In12.Cu" "In13.Cu" "In14.Cu"
			"In15.Cu" "In16.Cu"
		)
		(hatch none 0.5)
		(connect_pads
			(clearance 0)
		)
		(min_thickness 0.25)
		(keepout
			(tracks not_allowed)
			(vias allowed)
			(pads allowed)
			(copperpour not_allowed)
			(footprints allowed)
		)
		(placement
			(enabled no)
			(sheetname "")
		)
		(fill
			(thermal_gap 0.5)
			(thermal_bridge_width 0.5)
			(island_removal_mode 0)
		)
		(polygon
			(pts
				(arc
					(start 46.573694 -18.75536)
					(mid 46.192694 -19.13636)
					(end 46.573694 -19.51736)
				)
				(arc
					(start 47.437294 -19.51736)
					(mid 47.818294 -19.13636)
					(end 47.437294 -18.75536)
				)
			)
		)
	)
	(zone
		(layers "F.Cu" "B.Cu" "In1.Cu" "In2.Cu" "In3.Cu" "In4.Cu" "In5.Cu" "In6.Cu"
			"In7.Cu" "In8.Cu" "In9.Cu" "In10.Cu" "In11.Cu" "In12.Cu" "In13.Cu" "In14.Cu"
			"In15.Cu" "In16.Cu"
		)
		(hatch none 0.5)
		(connect_pads
			(clearance 0)
		)
		(min_thickness 0.25)
		(keepout
			(tracks not_allowed)
			(vias allowed)
			(pads allowed)
			(copperpour not_allowed)
			(footprints allowed)
		)
		(placement
			(enabled no)
			(sheetname "")
		)
		(fill
			(thermal_gap 0.5)
			(thermal_bridge_width 0.5)
			(island_removal_mode 0)
		)
		(polygon
			(pts
				(arc
					(start 99.203764 -289.807142)
					(mid 99.861624 -289.807142)
					(end 99.203764 -289.807142)
				)
			)
		)
	)
	(zone
		(layers "F.Cu" "B.Cu" "In1.Cu" "In2.Cu" "In3.Cu" "In4.Cu" "In5.Cu" "In6.Cu"
			"In7.Cu" "In8.Cu" "In9.Cu" "In10.Cu" "In11.Cu" "In12.Cu" "In13.Cu" "In14.Cu"
			"In15.Cu" "In16.Cu"
		)
		(hatch none 0.5)
		(connect_pads
			(clearance 0)
		)
		(min_thickness 0.25)
		(keepout
			(tracks not_allowed)
			(vias allowed)
			(pads allowed)
			(copperpour not_allowed)
			(footprints allowed)
		)
		(placement
			(enabled no)
			(sheetname "")
		)
		(fill
			(thermal_gap 0.5)
			(thermal_bridge_width 0.5)
			(island_removal_mode 0)
		)
		(polygon
			(pts
				(arc
					(start 331.549248 -400.477228)
					(mid 331.168248 -400.858228)
					(end 331.549248 -401.239228)
				)
				(arc
					(start 332.412848 -401.239228)
					(mid 332.793848 -400.858228)
					(end 332.412848 -400.477228)
				)
			)
		)
	)
	(zone
		(layers "F.Cu" "B.Cu" "In1.Cu" "In2.Cu" "In3.Cu" "In4.Cu" "In5.Cu" "In6.Cu"
			"In7.Cu" "In8.Cu" "In9.Cu" "In10.Cu" "In11.Cu" "In12.Cu" "In13.Cu" "In14.Cu"
			"In15.Cu" "In16.Cu"
		)
		(hatch none 0.5)
		(connect_pads
			(clearance 0)
		)
		(min_thickness 0.25)
		(keepout
			(tracks not_allowed)
			(vias allowed)
			(pads allowed)
			(copperpour not_allowed)
			(footprints allowed)
		)
		(placement
			(enabled no)
			(sheetname "")
		)
		(fill
			(thermal_gap 0.5)
			(thermal_bridge_width 0.5)
			(island_removal_mode 0)
		)
		(polygon
			(pts
				(arc
					(start 340.64321 -220.319854)
					(mid 339.98535 -220.319854)
					(end 340.64321 -220.319854)
				)
			)
		)
	)
	(zone
		(layers "F.Cu" "B.Cu" "In1.Cu" "In2.Cu" "In3.Cu" "In4.Cu" "In5.Cu" "In6.Cu"
			"In7.Cu" "In8.Cu" "In9.Cu" "In10.Cu" "In11.Cu" "In12.Cu" "In13.Cu" "In14.Cu"
			"In15.Cu" "In16.Cu"
		)
		(hatch none 0.5)
		(connect_pads
			(clearance 0)
		)
		(min_thickness 0.25)
		(keepout
			(tracks not_allowed)
			(vias allowed)
			(pads allowed)
			(copperpour not_allowed)
			(footprints allowed)
		)
		(placement
			(enabled no)
			(sheetname "")
		)
		(fill
			(thermal_gap 0.5)
			(thermal_bridge_width 0.5)
			(island_removal_mode 0)
		)
		(polygon
			(pts
				(arc
					(start 102.985062 -288.831274)
					(mid 102.917354 -288.759423)
					(end 102.822248 -288.732976)
				)
				(arc
					(start 102.822248 -288.732976)
					(mid 102.692034 -288.786912)
					(end 102.638098 -288.917126)
				)
				(arc
					(start 102.638098 -288.917126)
					(mid 102.643549 -288.961347)
					(end 102.659434 -289.002978)
				)
				(arc
					(start 103.12908 -289.892994)
					(mid 103.196788 -289.964845)
					(end 103.291894 -289.991292)
				)
				(arc
					(start 103.291894 -289.991292)
					(mid 103.422108 -289.937356)
					(end 103.476044 -289.807142)
				)
				(arc
					(start 103.476044 -289.807142)
					(mid 103.470593 -289.762921)
					(end 103.454708 -289.72129)
				)
			)
		)
	)
	(zone
		(layers "F.Cu" "B.Cu" "In1.Cu" "In2.Cu" "In3.Cu" "In4.Cu" "In5.Cu" "In6.Cu"
			"In7.Cu" "In8.Cu" "In9.Cu" "In10.Cu" "In11.Cu" "In12.Cu" "In13.Cu" "In14.Cu"
			"In15.Cu" "In16.Cu"
		)
		(hatch none 0.5)
		(connect_pads
			(clearance 0)
		)
		(min_thickness 0.25)
		(keepout
			(tracks not_allowed)
			(vias allowed)
			(pads allowed)
			(copperpour not_allowed)
			(footprints allowed)
		)
		(placement
			(enabled no)
			(sheetname "")
		)
		(fill
			(thermal_gap 0.5)
			(thermal_bridge_width 0.5)
			(island_removal_mode 0)
		)
		(polygon
			(pts
				(arc
					(start 132.126228 -285.759652)
					(mid 132.145912 -285.712242)
					(end 132.152644 -285.661354)
				)
				(arc
					(start 132.152644 -285.661354)
					(mid 132.094988 -285.52216)
					(end 131.955794 -285.464504)
				)
				(arc
					(start 131.955794 -285.464504)
					(mid 131.857363 -285.49092)
					(end 131.78536 -285.563056)
				)
				(arc
					(start 131.315714 -286.377126)
					(mid 131.29603 -286.424536)
					(end 131.289298 -286.475424)
				)
				(arc
					(start 131.289298 -286.475424)
					(mid 131.346954 -286.614618)
					(end 131.486148 -286.672274)
				)
				(arc
					(start 131.486148 -286.672274)
					(mid 131.584579 -286.645858)
					(end 131.656582 -286.573722)
				)
			)
		)
	)
	(zone
		(layers "F.Cu" "B.Cu" "In1.Cu" "In2.Cu" "In3.Cu" "In4.Cu" "In5.Cu" "In6.Cu"
			"In7.Cu" "In8.Cu" "In9.Cu" "In10.Cu" "In11.Cu" "In12.Cu" "In13.Cu" "In14.Cu"
			"In15.Cu" "In16.Cu"
		)
		(hatch none 0.5)
		(connect_pads
			(clearance 0)
		)
		(min_thickness 0.25)
		(keepout
			(tracks not_allowed)
			(vias allowed)
			(pads allowed)
			(copperpour not_allowed)
			(footprints allowed)
		)
		(placement
			(enabled no)
			(sheetname "")
		)
		(fill
			(thermal_gap 0.5)
			(thermal_bridge_width 0.5)
			(island_removal_mode 0)
		)
		(polygon
			(pts
				(arc
					(start 342.413336 -71.566786)
					(mid 342.794336 -71.185786)
					(end 342.413336 -70.804786)
				)
				(arc
					(start 341.549736 -70.804786)
					(mid 341.168736 -71.185786)
					(end 341.549736 -71.566786)
				)
			)
		)
	)
	(zone
		(layers "F.Cu" "B.Cu" "In1.Cu" "In2.Cu" "In3.Cu" "In4.Cu" "In5.Cu" "In6.Cu"
			"In7.Cu" "In8.Cu" "In9.Cu" "In10.Cu" "In11.Cu" "In12.Cu" "In13.Cu" "In14.Cu"
			"In15.Cu" "In16.Cu"
		)
		(hatch none 0.5)
		(connect_pads
			(clearance 0)
		)
		(min_thickness 0.25)
		(keepout
			(tracks not_allowed)
			(vias allowed)
			(pads allowed)
			(copperpour not_allowed)
			(footprints allowed)
		)
		(placement
			(enabled no)
			(sheetname "")
		)
		(fill
			(thermal_gap 0.5)
			(thermal_bridge_width 0.5)
			(island_removal_mode 0)
		)
		(polygon
			(pts
				(arc
					(start 118.359682 -220.319854)
					(mid 119.017542 -220.319854)
					(end 118.359682 -220.319854)
				)
			)
		)
	)
	(zone
		(layers "F.Cu" "B.Cu" "In1.Cu" "In2.Cu" "In3.Cu" "In4.Cu" "In5.Cu" "In6.Cu"
			"In7.Cu" "In8.Cu" "In9.Cu" "In10.Cu" "In11.Cu" "In12.Cu" "In13.Cu" "In14.Cu"
			"In15.Cu" "In16.Cu"
		)
		(hatch none 0.5)
		(connect_pads
			(clearance 0)
		)
		(min_thickness 0.25)
		(keepout
			(tracks not_allowed)
			(vias allowed)
			(pads allowed)
			(copperpour not_allowed)
			(footprints allowed)
		)
		(placement
			(enabled no)
			(sheetname "")
		)
		(fill
			(thermal_gap 0.5)
			(thermal_bridge_width 0.5)
			(island_removal_mode 0)
		)
		(polygon
			(pts
				(arc
					(start 344.243914 -223.67367)
					(mid 344.263598 -223.62626)
					(end 344.27033 -223.575372)
				)
				(arc
					(start 344.27033 -223.575372)
					(mid 344.212674 -223.436178)
					(end 344.07348 -223.378522)
				)
				(arc
					(start 344.07348 -223.378522)
					(mid 343.975049 -223.404938)
					(end 343.903046 -223.477074)
				)
				(arc
					(start 343.4334 -224.291144)
					(mid 343.413716 -224.338554)
					(end 343.406984 -224.389442)
				)
				(arc
					(start 343.406984 -224.389442)
					(mid 343.46464 -224.528636)
					(end 343.603834 -224.586292)
				)
				(arc
					(start 343.603834 -224.586292)
					(mid 343.702265 -224.559876)
					(end 343.774268 -224.48774)
				)
			)
		)
	)
	(zone
		(layers "F.Cu" "B.Cu" "In1.Cu" "In2.Cu" "In3.Cu" "In4.Cu" "In5.Cu" "In6.Cu"
			"In7.Cu" "In8.Cu" "In9.Cu" "In10.Cu" "In11.Cu" "In12.Cu" "In13.Cu" "In14.Cu"
			"In15.Cu" "In16.Cu"
		)
		(hatch none 0.5)
		(connect_pads
			(clearance 0)
		)
		(min_thickness 0.25)
		(keepout
			(tracks not_allowed)
			(vias allowed)
			(pads allowed)
			(copperpour not_allowed)
			(footprints allowed)
		)
		(placement
			(enabled no)
			(sheetname "")
		)
		(fill
			(thermal_gap 0.5)
			(thermal_bridge_width 0.5)
			(island_removal_mode 0)
		)
		(polygon
			(pts
				(arc
					(start 351.754948 -213.646766)
					(mid 351.68724 -213.574915)
					(end 351.592134 -213.548468)
				)
				(arc
					(start 351.592134 -213.548468)
					(mid 351.46192 -213.602404)
					(end 351.407984 -213.732618)
				)
				(arc
					(start 351.407984 -213.732618)
					(mid 351.413435 -213.776839)
					(end 351.42932 -213.81847)
				)
				(arc
					(start 351.898712 -214.708486)
					(mid 351.96642 -214.780337)
					(end 352.061526 -214.806784)
				)
				(arc
					(start 352.061526 -214.806784)
					(mid 352.19174 -214.752848)
					(end 352.245676 -214.622634)
				)
				(arc
					(start 352.245676 -214.622634)
					(mid 352.240225 -214.578413)
					(end 352.22434 -214.536782)
				)
			)
		)
	)
	(zone
		(layers "F.Cu" "B.Cu" "In1.Cu" "In2.Cu" "In3.Cu" "In4.Cu" "In5.Cu" "In6.Cu"
			"In7.Cu" "In8.Cu" "In9.Cu" "In10.Cu" "In11.Cu" "In12.Cu" "In13.Cu" "In14.Cu"
			"In15.Cu" "In16.Cu"
		)
		(hatch none 0.5)
		(connect_pads
			(clearance 0)
		)
		(min_thickness 0.25)
		(keepout
			(tracks not_allowed)
			(vias allowed)
			(pads allowed)
			(copperpour not_allowed)
			(footprints allowed)
		)
		(placement
			(enabled no)
			(sheetname "")
		)
		(fill
			(thermal_gap 0.5)
			(thermal_bridge_width 0.5)
			(island_removal_mode 0)
		)
		(polygon
			(pts
				(arc
					(start 317.579248 -409.649168)
					(mid 317.198248 -410.030168)
					(end 317.579248 -410.411168)
				)
				(arc
					(start 318.442848 -410.411168)
					(mid 318.823848 -410.030168)
					(end 318.442848 -409.649168)
				)
			)
		)
	)
	(zone
		(layers "F.Cu" "B.Cu" "In1.Cu" "In2.Cu" "In3.Cu" "In4.Cu" "In5.Cu" "In6.Cu"
			"In7.Cu" "In8.Cu" "In9.Cu" "In10.Cu" "In11.Cu" "In12.Cu" "In13.Cu" "In14.Cu"
			"In15.Cu" "In16.Cu"
		)
		(hatch none 0.5)
		(connect_pads
			(clearance 0)
		)
		(min_thickness 0.25)
		(keepout
			(tracks not_allowed)
			(vias allowed)
			(pads allowed)
			(copperpour not_allowed)
			(footprints allowed)
		)
		(placement
			(enabled no)
			(sheetname "")
		)
		(fill
			(thermal_gap 0.5)
			(thermal_bridge_width 0.5)
			(island_removal_mode 0)
		)
		(polygon
			(pts
				(arc
					(start 327.352914 2.491994)
					(mid 327.733914 2.110994)
					(end 328.114914 2.491994)
				)
				(arc
					(start 328.114914 3.355594)
					(mid 327.733914 3.736594)
					(end 327.352914 3.355594)
				)
			)
		)
	)
	(zone
		(layers "F.Cu" "B.Cu" "In1.Cu" "In2.Cu" "In3.Cu" "In4.Cu" "In5.Cu" "In6.Cu"
			"In7.Cu" "In8.Cu" "In9.Cu" "In10.Cu" "In11.Cu" "In12.Cu" "In13.Cu" "In14.Cu"
			"In15.Cu" "In16.Cu"
		)
		(hatch none 0.5)
		(connect_pads
			(clearance 0)
		)
		(min_thickness 0.25)
		(keepout
			(tracks not_allowed)
			(vias allowed)
			(pads allowed)
			(copperpour not_allowed)
			(footprints allowed)
		)
		(placement
			(enabled no)
			(sheetname "")
		)
		(fill
			(thermal_gap 0.5)
			(thermal_bridge_width 0.5)
			(island_removal_mode 0)
		)
		(polygon
			(pts
				(arc
					(start 357.089964 -217.878406)
					(mid 356.432104 -217.878406)
					(end 357.089964 -217.878406)
				)
			)
		)
	)
	(zone
		(layers "F.Cu" "B.Cu" "In1.Cu" "In2.Cu" "In3.Cu" "In4.Cu" "In5.Cu" "In6.Cu"
			"In7.Cu" "In8.Cu" "In9.Cu" "In10.Cu" "In11.Cu" "In12.Cu" "In13.Cu" "In14.Cu"
			"In15.Cu" "In16.Cu"
		)
		(hatch none 0.5)
		(connect_pads
			(clearance 0)
		)
		(min_thickness 0.25)
		(keepout
			(tracks not_allowed)
			(vias allowed)
			(pads allowed)
			(copperpour not_allowed)
			(footprints allowed)
		)
		(placement
			(enabled no)
			(sheetname "")
		)
		(fill
			(thermal_gap 0.5)
			(thermal_bridge_width 0.5)
			(island_removal_mode 0)
		)
		(polygon
			(pts
				(arc
					(start 125.126496 -217.878406)
					(mid 124.468636 -217.878406)
					(end 125.126496 -217.878406)
				)
			)
		)
	)
	(zone
		(layers "F.Cu" "B.Cu" "In1.Cu" "In2.Cu" "In3.Cu" "In4.Cu" "In5.Cu" "In6.Cu"
			"In7.Cu" "In8.Cu" "In9.Cu" "In10.Cu" "In11.Cu" "In12.Cu" "In13.Cu" "In14.Cu"
			"In15.Cu" "In16.Cu"
		)
		(hatch none 0.5)
		(connect_pads
			(clearance 0)
		)
		(min_thickness 0.25)
		(keepout
			(tracks not_allowed)
			(vias allowed)
			(pads allowed)
			(copperpour not_allowed)
			(footprints allowed)
		)
		(placement
			(enabled no)
			(sheetname "")
		)
		(fill
			(thermal_gap 0.5)
			(thermal_bridge_width 0.5)
			(island_removal_mode 0)
		)
		(polygon
			(pts
				(arc
					(start 134.31774 -24.065738)
					(mid 133.93674 -23.684738)
					(end 133.55574 -24.065738)
				)
				(arc
					(start 133.55574 -24.929338)
					(mid 133.93674 -25.310338)
					(end 134.31774 -24.929338)
				)
			)
		)
	)
	(zone
		(layers "F.Cu" "B.Cu" "In1.Cu" "In2.Cu" "In3.Cu" "In4.Cu" "In5.Cu" "In6.Cu"
			"In7.Cu" "In8.Cu" "In9.Cu" "In10.Cu" "In11.Cu" "In12.Cu" "In13.Cu" "In14.Cu"
			"In15.Cu" "In16.Cu"
		)
		(hatch none 0.5)
		(connect_pads
			(clearance 0)
		)
		(min_thickness 0.25)
		(keepout
			(tracks not_allowed)
			(vias allowed)
			(pads allowed)
			(copperpour not_allowed)
			(footprints allowed)
		)
		(placement
			(enabled no)
			(sheetname "")
		)
		(fill
			(thermal_gap 0.5)
			(thermal_bridge_width 0.5)
			(island_removal_mode 0)
		)
		(polygon
			(pts
				(arc
					(start 129.355342 -218.692222)
					(mid 128.697482 -218.692222)
					(end 129.355342 -218.692222)
				)
			)
		)
	)
	(zone
		(layers "F.Cu" "B.Cu" "In1.Cu" "In2.Cu" "In3.Cu" "In4.Cu" "In5.Cu" "In6.Cu"
			"In7.Cu" "In8.Cu" "In9.Cu" "In10.Cu" "In11.Cu" "In12.Cu" "In13.Cu" "In14.Cu"
			"In15.Cu" "In16.Cu"
		)
		(hatch none 0.5)
		(connect_pads
			(clearance 0)
		)
		(min_thickness 0.25)
		(keepout
			(tracks not_allowed)
			(vias allowed)
			(pads allowed)
			(copperpour not_allowed)
			(footprints allowed)
		)
		(placement
			(enabled no)
			(sheetname "")
		)
		(fill
			(thermal_gap 0.5)
			(thermal_bridge_width 0.5)
			(island_removal_mode 0)
		)
		(polygon
			(pts
				(arc
					(start 119.487696 -217.878406)
					(mid 118.829836 -217.878406)
					(end 119.487696 -217.878406)
				)
			)
		)
	)
	(zone
		(layers "F.Cu" "B.Cu" "In1.Cu" "In2.Cu" "In3.Cu" "In4.Cu" "In5.Cu" "In6.Cu"
			"In7.Cu" "In8.Cu" "In9.Cu" "In10.Cu" "In11.Cu" "In12.Cu" "In13.Cu" "In14.Cu"
			"In15.Cu" "In16.Cu"
		)
		(hatch none 0.5)
		(connect_pads
			(clearance 0)
		)
		(min_thickness 0.25)
		(keepout
			(tracks not_allowed)
			(vias allowed)
			(pads allowed)
			(copperpour not_allowed)
			(footprints allowed)
		)
		(placement
			(enabled no)
			(sheetname "")
		)
		(fill
			(thermal_gap 0.5)
			(thermal_bridge_width 0.5)
			(island_removal_mode 0)
		)
		(polygon
			(pts
				(arc
					(start 118.547896 -224.389442)
					(mid 117.890036 -224.389442)
					(end 118.547896 -224.389442)
				)
			)
		)
	)
	(zone
		(layers "F.Cu" "B.Cu" "In1.Cu" "In2.Cu" "In3.Cu" "In4.Cu" "In5.Cu" "In6.Cu"
			"In7.Cu" "In8.Cu" "In9.Cu" "In10.Cu" "In11.Cu" "In12.Cu" "In13.Cu" "In14.Cu"
			"In15.Cu" "In16.Cu"
		)
		(hatch none 0.5)
		(connect_pads
			(clearance 0)
		)
		(min_thickness 0.25)
		(keepout
			(tracks not_allowed)
			(vias allowed)
			(pads allowed)
			(copperpour not_allowed)
			(footprints allowed)
		)
		(placement
			(enabled no)
			(sheetname "")
		)
		(fill
			(thermal_gap 0.5)
			(thermal_bridge_width 0.5)
			(island_removal_mode 0)
		)
		(polygon
			(pts
				(arc
					(start 337.845654 -136.791446)
					(mid 337.464654 -137.172446)
					(end 337.845654 -137.553446)
				)
				(arc
					(start 338.618322 -137.553446)
					(mid 338.999322 -137.172446)
					(end 338.618322 -136.791446)
				)
			)
		)
	)
	(zone
		(layers "F.Cu" "B.Cu" "In1.Cu" "In2.Cu" "In3.Cu" "In4.Cu" "In5.Cu" "In6.Cu"
			"In7.Cu" "In8.Cu" "In9.Cu" "In10.Cu" "In11.Cu" "In12.Cu" "In13.Cu" "In14.Cu"
			"In15.Cu" "In16.Cu"
		)
		(hatch none 0.5)
		(connect_pads
			(clearance 0)
		)
		(min_thickness 0.25)
		(keepout
			(tracks not_allowed)
			(vias allowed)
			(pads allowed)
			(copperpour not_allowed)
			(footprints allowed)
		)
		(placement
			(enabled no)
			(sheetname "")
		)
		(fill
			(thermal_gap 0.5)
			(thermal_bridge_width 0.5)
			(island_removal_mode 0)
		)
		(polygon
			(pts
				(arc
					(start 343.77376 -214.720932)
					(mid 343.793444 -214.673522)
					(end 343.800176 -214.622634)
				)
				(arc
					(start 343.800176 -214.622634)
					(mid 343.74252 -214.48344)
					(end 343.603326 -214.425784)
				)
				(arc
					(start 343.603326 -214.425784)
					(mid 343.504895 -214.4522)
					(end 343.432892 -214.524336)
				)
				(arc
					(start 342.963246 -215.338406)
					(mid 342.943562 -215.385816)
					(end 342.93683 -215.436704)
				)
				(arc
					(start 342.93683 -215.436704)
					(mid 342.994486 -215.575898)
					(end 343.13368 -215.633554)
				)
				(arc
					(start 343.13368 -215.633554)
					(mid 343.232111 -215.607138)
					(end 343.304114 -215.535002)
				)
			)
		)
	)
	(zone
		(layers "F.Cu" "B.Cu" "In1.Cu" "In2.Cu" "In3.Cu" "In4.Cu" "In5.Cu" "In6.Cu"
			"In7.Cu" "In8.Cu" "In9.Cu" "In10.Cu" "In11.Cu" "In12.Cu" "In13.Cu" "In14.Cu"
			"In15.Cu" "In16.Cu"
		)
		(hatch none 0.5)
		(connect_pads
			(clearance 0)
		)
		(min_thickness 0.25)
		(keepout
			(tracks not_allowed)
			(vias allowed)
			(pads allowed)
			(copperpour not_allowed)
			(footprints allowed)
		)
		(placement
			(enabled no)
			(sheetname "")
		)
		(fill
			(thermal_gap 0.5)
			(thermal_bridge_width 0.5)
			(island_removal_mode 0)
		)
		(polygon
			(pts
				(arc
					(start 104.450896 -217.878406)
					(mid 103.793036 -217.878406)
					(end 104.450896 -217.878406)
				)
			)
		)
	)
	(zone
		(layers "F.Cu" "B.Cu" "In1.Cu" "In2.Cu" "In3.Cu" "In4.Cu" "In5.Cu" "In6.Cu"
			"In7.Cu" "In8.Cu" "In9.Cu" "In10.Cu" "In11.Cu" "In12.Cu" "In13.Cu" "In14.Cu"
			"In15.Cu" "In16.Cu"
		)
		(hatch none 0.5)
		(connect_pads
			(clearance 0)
		)
		(min_thickness 0.25)
		(keepout
			(tracks not_allowed)
			(vias allowed)
			(pads allowed)
			(copperpour not_allowed)
			(footprints allowed)
		)
		(placement
			(enabled no)
			(sheetname "")
		)
		(fill
			(thermal_gap 0.5)
			(thermal_bridge_width 0.5)
			(island_removal_mode 0)
		)
		(polygon
			(pts
				(arc
					(start 107.192064 -277.522432)
					(mid 107.849924 -277.522432)
					(end 107.192064 -277.522432)
				)
			)
		)
	)
	(zone
		(layers "F.Cu" "B.Cu" "In1.Cu" "In2.Cu" "In3.Cu" "In4.Cu" "In5.Cu" "In6.Cu"
			"In7.Cu" "In8.Cu" "In9.Cu" "In10.Cu" "In11.Cu" "In12.Cu" "In13.Cu" "In14.Cu"
			"In15.Cu" "In16.Cu"
		)
		(hatch none 0.5)
		(connect_pads
			(clearance 0)
		)
		(min_thickness 0.25)
		(keepout
			(tracks not_allowed)
			(vias allowed)
			(pads allowed)
			(copperpour not_allowed)
			(footprints allowed)
		)
		(placement
			(enabled no)
			(sheetname "")
		)
		(fill
			(thermal_gap 0.5)
			(thermal_bridge_width 0.5)
			(island_removal_mode 0)
		)
		(polygon
			(pts
				(arc
					(start 351.560892 -289.807142)
					(mid 350.903032 -289.807142)
					(end 351.560892 -289.807142)
				)
			)
		)
	)
	(zone
		(layers "F.Cu" "B.Cu" "In1.Cu" "In2.Cu" "In3.Cu" "In4.Cu" "In5.Cu" "In6.Cu"
			"In7.Cu" "In8.Cu" "In9.Cu" "In10.Cu" "In11.Cu" "In12.Cu" "In13.Cu" "In14.Cu"
			"In15.Cu" "In16.Cu"
		)
		(hatch none 0.5)
		(connect_pads
			(clearance 0)
		)
		(min_thickness 0.25)
		(keepout
			(tracks not_allowed)
			(vias allowed)
			(pads allowed)
			(copperpour not_allowed)
			(footprints allowed)
		)
		(placement
			(enabled no)
			(sheetname "")
		)
		(fill
			(thermal_gap 0.5)
			(thermal_bridge_width 0.5)
			(island_removal_mode 0)
		)
		(polygon
			(pts
				(arc
					(start 122.306588 -214.622634)
					(mid 121.648728 -214.622634)
					(end 122.306588 -214.622634)
				)
			)
		)
	)
	(zone
		(layers "F.Cu" "B.Cu" "In1.Cu" "In2.Cu" "In3.Cu" "In4.Cu" "In5.Cu" "In6.Cu"
			"In7.Cu" "In8.Cu" "In9.Cu" "In10.Cu" "In11.Cu" "In12.Cu" "In13.Cu" "In14.Cu"
			"In15.Cu" "In16.Cu"
		)
		(hatch none 0.5)
		(connect_pads
			(clearance 0)
		)
		(min_thickness 0.25)
		(keepout
			(tracks not_allowed)
			(vias allowed)
			(pads allowed)
			(copperpour not_allowed)
			(footprints allowed)
		)
		(placement
			(enabled no)
			(sheetname "")
		)
		(fill
			(thermal_gap 0.5)
			(thermal_bridge_width 0.5)
			(island_removal_mode 0)
		)
		(polygon
			(pts
				(arc
					(start 130.716782 -284.74924)
					(mid 130.644793 -284.677081)
					(end 130.546348 -284.650688)
				)
				(arc
					(start 130.546348 -284.650688)
					(mid 130.407154 -284.708344)
					(end 130.349498 -284.847538)
				)
				(arc
					(start 130.349498 -284.847538)
					(mid 130.356255 -284.898419)
					(end 130.375914 -284.945836)
				)
				(arc
					(start 130.84556 -285.759652)
					(mid 130.917549 -285.831811)
					(end 131.015994 -285.858204)
				)
				(arc
					(start 131.015994 -285.858204)
					(mid 131.155188 -285.800548)
					(end 131.212844 -285.661354)
				)
				(arc
					(start 131.212844 -285.661354)
					(mid 131.206087 -285.610473)
					(end 131.186428 -285.563056)
				)
			)
		)
	)
	(zone
		(layers "F.Cu" "B.Cu" "In1.Cu" "In2.Cu" "In3.Cu" "In4.Cu" "In5.Cu" "In6.Cu"
			"In7.Cu" "In8.Cu" "In9.Cu" "In10.Cu" "In11.Cu" "In12.Cu" "In13.Cu" "In14.Cu"
			"In15.Cu" "In16.Cu"
		)
		(hatch none 0.5)
		(connect_pads
			(clearance 0)
		)
		(min_thickness 0.25)
		(keepout
			(tracks not_allowed)
			(vias allowed)
			(pads allowed)
			(copperpour not_allowed)
			(footprints allowed)
		)
		(placement
			(enabled no)
			(sheetname "")
		)
		(fill
			(thermal_gap 0.5)
			(thermal_bridge_width 0.5)
			(island_removal_mode 0)
		)
		(polygon
			(pts
				(arc
					(start 346.392246 -288.917126)
					(mid 345.734386 -288.917126)
					(end 346.392246 -288.917126)
				)
			)
		)
	)
	(zone
		(layers "F.Cu" "B.Cu" "In1.Cu" "In2.Cu" "In3.Cu" "In4.Cu" "In5.Cu" "In6.Cu"
			"In7.Cu" "In8.Cu" "In9.Cu" "In10.Cu" "In11.Cu" "In12.Cu" "In13.Cu" "In14.Cu"
			"In15.Cu" "In16.Cu"
		)
		(hatch none 0.5)
		(connect_pads
			(clearance 0)
		)
		(min_thickness 0.25)
		(keepout
			(tracks not_allowed)
			(vias allowed)
			(pads allowed)
			(copperpour not_allowed)
			(footprints allowed)
		)
		(placement
			(enabled no)
			(sheetname "")
		)
		(fill
			(thermal_gap 0.5)
			(thermal_bridge_width 0.5)
			(island_removal_mode 0)
		)
		(polygon
			(pts
				(arc
					(start 345.34221 -215.436704)
					(mid 344.68435 -215.436704)
					(end 345.34221 -215.436704)
				)
			)
		)
	)
	(zone
		(layers "F.Cu" "B.Cu" "In1.Cu" "In2.Cu" "In3.Cu" "In4.Cu" "In5.Cu" "In6.Cu"
			"In7.Cu" "In8.Cu" "In9.Cu" "In10.Cu" "In11.Cu" "In12.Cu" "In13.Cu" "In14.Cu"
			"In15.Cu" "In16.Cu"
		)
		(hatch none 0.5)
		(connect_pads
			(clearance 0)
		)
		(min_thickness 0.25)
		(keepout
			(tracks not_allowed)
			(vias allowed)
			(pads allowed)
			(copperpour not_allowed)
			(footprints allowed)
		)
		(placement
			(enabled no)
			(sheetname "")
		)
		(fill
			(thermal_gap 0.5)
			(thermal_bridge_width 0.5)
			(island_removal_mode 0)
		)
		(polygon
			(pts
				(arc
					(start 346.282264 -213.732618)
					(mid 345.624404 -213.732618)
					(end 346.282264 -213.732618)
				)
			)
		)
	)
	(zone
		(layers "F.Cu" "B.Cu" "In1.Cu" "In2.Cu" "In3.Cu" "In4.Cu" "In5.Cu" "In6.Cu"
			"In7.Cu" "In8.Cu" "In9.Cu" "In10.Cu" "In11.Cu" "In12.Cu" "In13.Cu" "In14.Cu"
			"In15.Cu" "In16.Cu"
		)
		(hatch none 0.5)
		(connect_pads
			(clearance 0)
		)
		(min_thickness 0.25)
		(keepout
			(tracks not_allowed)
			(vias allowed)
			(pads allowed)
			(copperpour not_allowed)
			(footprints allowed)
		)
		(placement
			(enabled no)
			(sheetname "")
		)
		(fill
			(thermal_gap 0.5)
			(thermal_bridge_width 0.5)
			(island_removal_mode 0)
		)
		(polygon
			(pts
				(arc
					(start 96.744282 -215.436704)
					(mid 97.402142 -215.436704)
					(end 96.744282 -215.436704)
				)
			)
		)
	)
	(zone
		(layers "F.Cu" "B.Cu" "In1.Cu" "In2.Cu" "In3.Cu" "In4.Cu" "In5.Cu" "In6.Cu"
			"In7.Cu" "In8.Cu" "In9.Cu" "In10.Cu" "In11.Cu" "In12.Cu" "In13.Cu" "In14.Cu"
			"In15.Cu" "In16.Cu"
		)
		(hatch none 0.5)
		(connect_pads
			(clearance 0)
		)
		(min_thickness 0.25)
		(keepout
			(tracks not_allowed)
			(vias allowed)
			(pads allowed)
			(copperpour not_allowed)
			(footprints allowed)
		)
		(placement
			(enabled no)
			(sheetname "")
		)
		(fill
			(thermal_gap 0.5)
			(thermal_bridge_width 0.5)
			(island_removal_mode 0)
		)
		(polygon
			(pts
				(arc
					(start 117.45214 -412.946088)
					(mid 117.07114 -412.565088)
					(end 116.69014 -412.946088)
				)
				(arc
					(start 116.69014 -413.809688)
					(mid 117.07114 -414.190688)
					(end 117.45214 -413.809688)
				)
			)
		)
	)
	(zone
		(layers "F.Cu" "B.Cu" "In1.Cu" "In2.Cu" "In3.Cu" "In4.Cu" "In5.Cu" "In6.Cu"
			"In7.Cu" "In8.Cu" "In9.Cu" "In10.Cu" "In11.Cu" "In12.Cu" "In13.Cu" "In14.Cu"
			"In15.Cu" "In16.Cu"
		)
		(hatch none 0.5)
		(connect_pads
			(clearance 0)
		)
		(min_thickness 0.25)
		(keepout
			(tracks not_allowed)
			(vias allowed)
			(pads allowed)
			(copperpour not_allowed)
			(footprints allowed)
		)
		(placement
			(enabled no)
			(sheetname "")
		)
		(fill
			(thermal_gap 0.5)
			(thermal_bridge_width 0.5)
			(island_removal_mode 0)
		)
		(polygon
			(pts
				(arc
					(start 343.46261 -215.436704)
					(mid 342.80475 -215.436704)
					(end 343.46261 -215.436704)
				)
			)
		)
	)
	(zone
		(layers "F.Cu" "B.Cu" "In1.Cu" "In2.Cu" "In3.Cu" "In4.Cu" "In5.Cu" "In6.Cu"
			"In7.Cu" "In8.Cu" "In9.Cu" "In10.Cu" "In11.Cu" "In12.Cu" "In13.Cu" "In14.Cu"
			"In15.Cu" "In16.Cu"
		)
		(hatch none 0.5)
		(connect_pads
			(clearance 0)
		)
		(min_thickness 0.25)
		(keepout
			(tracks not_allowed)
			(vias allowed)
			(pads allowed)
			(copperpour not_allowed)
			(footprints allowed)
		)
		(placement
			(enabled no)
			(sheetname "")
		)
		(fill
			(thermal_gap 0.5)
			(thermal_bridge_width 0.5)
			(island_removal_mode 0)
		)
		(polygon
			(pts
				(arc
					(start 132.754878 -284.847538)
					(mid 132.097018 -284.847538)
					(end 132.754878 -284.847538)
				)
			)
		)
	)
	(zone
		(layers "F.Cu" "B.Cu" "In1.Cu" "In2.Cu" "In3.Cu" "In4.Cu" "In5.Cu" "In6.Cu"
			"In7.Cu" "In8.Cu" "In9.Cu" "In10.Cu" "In11.Cu" "In12.Cu" "In13.Cu" "In14.Cu"
			"In15.Cu" "In16.Cu"
		)
		(hatch none 0.5)
		(connect_pads
			(clearance 0)
		)
		(min_thickness 0.25)
		(keepout
			(tracks not_allowed)
			(vias allowed)
			(pads allowed)
			(copperpour not_allowed)
			(footprints allowed)
		)
		(placement
			(enabled no)
			(sheetname "")
		)
		(fill
			(thermal_gap 0.5)
			(thermal_bridge_width 0.5)
			(island_removal_mode 0)
		)
		(polygon
			(pts
				(arc
					(start 131.234942 -221.94774)
					(mid 130.577082 -221.94774)
					(end 131.234942 -221.94774)
				)
			)
		)
	)
	(zone
		(layers "F.Cu" "B.Cu" "In1.Cu" "In2.Cu" "In3.Cu" "In4.Cu" "In5.Cu" "In6.Cu"
			"In7.Cu" "In8.Cu" "In9.Cu" "In10.Cu" "In11.Cu" "In12.Cu" "In13.Cu" "In14.Cu"
			"In15.Cu" "In16.Cu"
		)
		(hatch none 0.5)
		(connect_pads
			(clearance 0)
		)
		(min_thickness 0.25)
		(keepout
			(tracks not_allowed)
			(vias allowed)
			(pads allowed)
			(copperpour not_allowed)
			(footprints allowed)
		)
		(placement
			(enabled no)
			(sheetname "")
		)
		(fill
			(thermal_gap 0.5)
			(thermal_bridge_width 0.5)
			(island_removal_mode 0)
		)
		(polygon
			(pts
				(arc
					(start 104.842818 -283.219906)
					(mid 105.500678 -283.219906)
					(end 104.842818 -283.219906)
				)
			)
		)
	)
	(zone
		(layers "F.Cu" "B.Cu" "In1.Cu" "In2.Cu" "In3.Cu" "In4.Cu" "In5.Cu" "In6.Cu"
			"In7.Cu" "In8.Cu" "In9.Cu" "In10.Cu" "In11.Cu" "In12.Cu" "In13.Cu" "In14.Cu"
			"In15.Cu" "In16.Cu"
		)
		(hatch none 0.5)
		(connect_pads
			(clearance 0)
		)
		(min_thickness 0.25)
		(keepout
			(tracks not_allowed)
			(vias allowed)
			(pads allowed)
			(copperpour not_allowed)
			(footprints allowed)
		)
		(placement
			(enabled no)
			(sheetname "")
		)
		(fill
			(thermal_gap 0.5)
			(thermal_bridge_width 0.5)
			(island_removal_mode 0)
		)
		(polygon
			(pts
				(arc
					(start 100.613718 -288.917126)
					(mid 101.271578 -288.917126)
					(end 100.613718 -288.917126)
				)
			)
		)
	)
	(zone
		(layers "F.Cu" "B.Cu" "In1.Cu" "In2.Cu" "In3.Cu" "In4.Cu" "In5.Cu" "In6.Cu"
			"In7.Cu" "In8.Cu" "In9.Cu" "In10.Cu" "In11.Cu" "In12.Cu" "In13.Cu" "In14.Cu"
			"In15.Cu" "In16.Cu"
		)
		(hatch none 0.5)
		(connect_pads
			(clearance 0)
		)
		(min_thickness 0.25)
		(keepout
			(tracks not_allowed)
			(vias allowed)
			(pads allowed)
			(copperpour not_allowed)
			(footprints allowed)
		)
		(placement
			(enabled no)
			(sheetname "")
		)
		(fill
			(thermal_gap 0.5)
			(thermal_bridge_width 0.5)
			(island_removal_mode 0)
		)
		(polygon
			(pts
				(arc
					(start 123.246896 -224.389442)
					(mid 122.589036 -224.389442)
					(end 123.246896 -224.389442)
				)
			)
		)
	)
	(zone
		(layers "F.Cu" "B.Cu" "In1.Cu" "In2.Cu" "In3.Cu" "In4.Cu" "In5.Cu" "In6.Cu"
			"In7.Cu" "In8.Cu" "In9.Cu" "In10.Cu" "In11.Cu" "In12.Cu" "In13.Cu" "In14.Cu"
			"In15.Cu" "In16.Cu"
		)
		(hatch none 0.5)
		(connect_pads
			(clearance 0)
		)
		(min_thickness 0.25)
		(keepout
			(tracks not_allowed)
			(vias allowed)
			(pads allowed)
			(copperpour not_allowed)
			(footprints allowed)
		)
		(placement
			(enabled no)
			(sheetname "")
		)
		(fill
			(thermal_gap 0.5)
			(thermal_bridge_width 0.5)
			(island_removal_mode 0)
		)
		(polygon
			(pts
				(arc
					(start 358.969564 -224.389442)
					(mid 358.311704 -224.389442)
					(end 358.969564 -224.389442)
				)
			)
		)
	)
	(zone
		(layers "F.Cu" "B.Cu" "In1.Cu" "In2.Cu" "In3.Cu" "In4.Cu" "In5.Cu" "In6.Cu"
			"In7.Cu" "In8.Cu" "In9.Cu" "In10.Cu" "In11.Cu" "In12.Cu" "In13.Cu" "In14.Cu"
			"In15.Cu" "In16.Cu"
		)
		(hatch none 0.5)
		(connect_pads
			(clearance 0)
		)
		(min_thickness 0.25)
		(keepout
			(tracks not_allowed)
			(vias allowed)
			(pads allowed)
			(copperpour not_allowed)
			(footprints allowed)
		)
		(placement
			(enabled no)
			(sheetname "")
		)
		(fill
			(thermal_gap 0.5)
			(thermal_bridge_width 0.5)
			(island_removal_mode 0)
		)
		(polygon
			(pts
				(arc
					(start 107.740196 -213.732618)
					(mid 107.082336 -213.732618)
					(end 107.740196 -213.732618)
				)
			)
		)
	)
	(zone
		(layers "F.Cu" "B.Cu" "In1.Cu" "In2.Cu" "In3.Cu" "In4.Cu" "In5.Cu" "In6.Cu"
			"In7.Cu" "In8.Cu" "In9.Cu" "In10.Cu" "In11.Cu" "In12.Cu" "In13.Cu" "In14.Cu"
			"In15.Cu" "In16.Cu"
		)
		(hatch none 0.5)
		(connect_pads
			(clearance 0)
		)
		(min_thickness 0.25)
		(keepout
			(tracks not_allowed)
			(vias allowed)
			(pads allowed)
			(copperpour not_allowed)
			(footprints allowed)
		)
		(placement
			(enabled no)
			(sheetname "")
		)
		(fill
			(thermal_gap 0.5)
			(thermal_bridge_width 0.5)
			(island_removal_mode 0)
		)
		(polygon
			(pts
				(arc
					(start 108.961682 -215.436704)
					(mid 109.619542 -215.436704)
					(end 108.961682 -215.436704)
				)
			)
		)
	)
	(zone
		(layers "F.Cu" "B.Cu" "In1.Cu" "In2.Cu" "In3.Cu" "In4.Cu" "In5.Cu" "In6.Cu"
			"In7.Cu" "In8.Cu" "In9.Cu" "In10.Cu" "In11.Cu" "In12.Cu" "In13.Cu" "In14.Cu"
			"In15.Cu" "In16.Cu"
		)
		(hatch none 0.5)
		(connect_pads
			(clearance 0)
		)
		(min_thickness 0.25)
		(keepout
			(tracks not_allowed)
			(vias allowed)
			(pads allowed)
			(copperpour not_allowed)
			(footprints allowed)
		)
		(placement
			(enabled no)
			(sheetname "")
		)
		(fill
			(thermal_gap 0.5)
			(thermal_bridge_width 0.5)
			(island_removal_mode 0)
		)
		(polygon
			(pts
				(arc
					(start 182.422292 -47.164498)
					(mid 182.041292 -46.783498)
					(end 181.660292 -47.164498)
				)
				(arc
					(start 181.660292 -48.028098)
					(mid 182.041292 -48.409098)
					(end 182.422292 -48.028098)
				)
			)
		)
	)
	(zone
		(layers "F.Cu" "B.Cu" "In1.Cu" "In2.Cu" "In3.Cu" "In4.Cu" "In5.Cu" "In6.Cu"
			"In7.Cu" "In8.Cu" "In9.Cu" "In10.Cu" "In11.Cu" "In12.Cu" "In13.Cu" "In14.Cu"
			"In15.Cu" "In16.Cu"
		)
		(hatch none 0.5)
		(connect_pads
			(clearance 0)
		)
		(min_thickness 0.25)
		(keepout
			(tracks not_allowed)
			(vias allowed)
			(pads allowed)
			(copperpour not_allowed)
			(footprints allowed)
		)
		(placement
			(enabled no)
			(sheetname "")
		)
		(fill
			(thermal_gap 0.5)
			(thermal_bridge_width 0.5)
			(island_removal_mode 0)
		)
		(polygon
			(pts
				(arc
					(start 379.956822 -216.966292)
					(mid 379.884833 -216.894133)
					(end 379.786388 -216.86774)
				)
				(arc
					(start 379.786388 -216.86774)
					(mid 379.647194 -216.925396)
					(end 379.589538 -217.06459)
				)
				(arc
					(start 379.589538 -217.06459)
					(mid 379.596295 -217.115471)
					(end 379.615954 -217.162888)
				)
				(arc
					(start 380.0856 -217.976704)
					(mid 380.157589 -218.048863)
					(end 380.256034 -218.075256)
				)
				(arc
					(start 380.256034 -218.075256)
					(mid 380.395228 -218.0176)
					(end 380.452884 -217.878406)
				)
				(arc
					(start 380.452884 -217.878406)
					(mid 380.446127 -217.827525)
					(end 380.426468 -217.780108)
				)
			)
		)
	)
	(zone
		(layers "F.Cu" "B.Cu" "In1.Cu" "In2.Cu" "In3.Cu" "In4.Cu" "In5.Cu" "In6.Cu"
			"In7.Cu" "In8.Cu" "In9.Cu" "In10.Cu" "In11.Cu" "In12.Cu" "In13.Cu" "In14.Cu"
			"In15.Cu" "In16.Cu"
		)
		(name "Package Keepin")
		(hatch none 0.5)
		(connect_pads
			(clearance 0)
		)
		(min_thickness 0.25)
		(keepout
			(tracks allowed)
			(vias allowed)
			(pads allowed)
			(copperpour allowed)
			(footprints allowed)
		)
		(placement
			(enabled no)
			(sheetname "")
		)
		(fill
			(thermal_gap 0.5)
			(thermal_bridge_width 0.5)
			(island_removal_mode 0)
		)
		(polygon
			(pts
				(arc
					(start 83.70189 -12.796012)
					(mid 81.569259 -11.912647)
					(end 80.685894 -9.780016)
				)
				(xy 80.685894 -1.615948) (xy 80.685894 -1.016) (xy 14.118082 -1.016) (xy 14.118082 -1.615948)
				(arc
					(start 14.118082 -9.780016)
					(mid 13.234717 -11.912647)
					(end 11.102086 -12.796012)
				)
				(arc
					(start 1.999996 -12.796012)
					(mid 1.304206 -13.084218)
					(end 1.016 -13.780008)
				)
				(arc
					(start 1.016 -77.671676)
					(mid 1.090985 -78.048181)
					(end 1.30429 -78.367382)
				)
				(arc
					(start 2.132584 -79.19593)
					(mid 2.78636 -80.174236)
					(end 3.015996 -81.32826)
				)
				(arc
					(start 3.015996 -403.371812)
					(mid 3.090981 -403.748317)
					(end 3.304286 -404.067518)
				)
				(arc
					(start 6.632448 -407.39568)
					(mid 7.28641 -408.374074)
					(end 7.516114 -409.528264)
				)
				(xy 7.516114 -425.566078) (xy 7.516114 -425.755308)
				(arc
					(start 7.516114 -439.989976)
					(mid 7.80432 -440.685766)
					(end 8.50011 -440.973972)
				)
				(arc
					(start 194.001644 -440.973972)
					(mid 194.50471 -440.030753)
					(end 195.50507 -439.653934)
				)
				(arc
					(start 276.314916 -439.653934)
					(mid 277.315254 -440.030778)
					(end 277.818342 -440.973972)
				)
				(xy 450.202554 -440.973972) (xy 450.683884 -440.973972)
				(arc
					(start 463.300064 -440.973972)
					(mid 463.995854 -440.685766)
					(end 464.28406 -439.989976)
				)
				(xy 464.28406 -425.174664) (xy 464.28406 -424.86834) (xy 464.28406 -419.130988) (xy 467.68766 -419.130988)
				(xy 467.68766 -440.545728) (xy 468.72906 -441.587128) (xy 472.72448 -441.587128) (xy 474.28658 -443.149228)
				(xy 474.28658 -461.546448) (xy 474.28658 -472.3384) (xy 475.02572 -473.07754) (xy 532.04618 -473.07754)
				(xy 533.36444 -471.75928) (xy 533.36444 -461.536288) (xy 533.36444 -454.406508) (xy 532.35098 -453.393048)
				(xy 515.13486 -453.393048) (xy 513.7277 -451.985888) (xy 513.7277 -311.366408) (xy 515.1501 -309.944008)
				(xy 532.21128 -309.944008) (xy 533.36444 -308.790848) (xy 533.36444 10.984992) (xy 532.41956 11.929872)
				(xy 475.30258 11.929872) (xy 474.1926 10.819892) (xy 474.1926 -79.525368) (xy 470.69248 -83.025488)
				(xy 470.69248 -406.751028) (xy 467.6648 -409.778708) (xy 467.6648 -418.988748) (xy 464.28406 -418.988748)
				(arc
					(start 464.28406 -409.528264)
					(mid 464.513703 -408.374243)
					(end 465.167472 -407.395934)
				)
				(arc
					(start 466.995764 -405.567388)
					(mid 467.209125 -405.24821)
					(end 467.284054 -404.871682)
				)
				(arc
					(start 467.284054 -82.82813)
					(mid 467.513682 -81.674095)
					(end 468.167466 -80.6958)
				)
				(arc
					(start 470.49563 -78.367382)
					(mid 470.708991 -78.048204)
					(end 470.78392 -77.671676)
				)
				(arc
					(start 470.78392 -13.780008)
					(mid 470.495714 -13.084218)
					(end 469.799924 -12.796012)
				)
				(xy 464.49488 -12.796012) (xy 464.49488 -9.304528) (xy 470.27084 -9.304528) (xy 471.2589 -8.316468)
				(xy 471.2589 10.984992) (xy 470.31402 11.929872) (xy 20.93468 11.929872) (xy 20.92198 11.942572)
				(xy 1.37668 11.942572) (xy 0.42926 10.995152) (xy 0.42926 -8.336788) (xy 1.37668 -9.284208) (xy 9.72566 -9.284208)
				(xy 10.67054 -8.339328) (xy 10.67054 1.264412) (xy 12.39774 2.991612) (xy 82.47126 2.991612) (xy 84.1756 1.287272)
				(xy 84.1756 -8.407908) (xy 85.05952 -9.291828) (xy 122.69724 -9.291828) (xy 123.6726 -8.316468)
				(xy 123.6726 -3.985768) (xy 125.2093 -2.449068) (xy 195.6181 -2.449068) (xy 197.27164 -4.102608)
				(xy 197.27164 -8.407908) (xy 198.1708 -9.307068) (xy 224.23374 -9.307068) (xy 225.74504 -10.818368)
				(xy 225.74504 -30.853888) (xy 227.667058 -32.775906) (xy 254.379222 -32.775906) (xy 256.30378 -30.851348)
				(xy 256.30378 -10.937748) (xy 257.8989 -9.342628) (xy 384.11912 -9.342628) (xy 385.14782 -8.313928)
				(xy 385.14782 1.381252) (xy 386.6896 2.923032) (xy 457.05014 2.923032) (xy 458.65542 1.317752) (xy 458.65542 -8.161528)
				(xy 459.80096 -9.307068) (xy 464.37804 -9.307068) (xy 464.37804 -12.796012)
				(arc
					(start 458.20203 -12.796012)
					(mid 456.069399 -11.912647)
					(end 455.186034 -9.780016)
				)
				(xy 455.186034 -1.615948) (xy 455.186034 -1.016) (xy 388.617968 -1.016) (xy 388.617968 -1.615948)
				(arc
					(start 388.617968 -9.780016)
					(mid 387.734603 -11.912647)
					(end 385.601972 -12.796012)
				)
				(arc
					(start 260.800088 -12.796012)
					(mid 260.104298 -13.084218)
					(end 259.816092 -13.780008)
				)
				(xy 259.816092 -32.275018)
				(arc
					(start 259.816092 -33.275016)
					(mid 258.932727 -35.407647)
					(end 256.800096 -36.291012)
				)
				(arc
					(start 225.300032 -36.291012)
					(mid 223.167401 -35.407647)
					(end 222.284036 -33.275016)
				)
				(xy 222.284036 -32.275018)
				(arc
					(start 222.284036 -13.780008)
					(mid 221.99583 -13.084218)
					(end 221.30004 -12.796012)
				)
				(arc
					(start 196.701918 -12.796012)
					(mid 194.569287 -11.912647)
					(end 193.685922 -9.780016)
				)
				(xy 193.685922 -6.895846) (xy 193.685922 -6.295898) (xy 127.11811 -6.295898) (xy 127.11811 -6.895846)
				(arc
					(start 127.11811 -9.780016)
					(mid 126.234745 -11.912647)
					(end 124.102114 -12.796012)
				)
			)
		)
	)
	(zone
		(layers "F.Cu" "B.Cu" "In1.Cu" "In2.Cu" "In3.Cu" "In4.Cu" "In5.Cu" "In6.Cu"
			"In7.Cu" "In8.Cu" "In9.Cu" "In10.Cu" "In11.Cu" "In12.Cu" "In13.Cu" "In14.Cu"
			"In15.Cu" "In16.Cu"
		)
		(hatch none 0.5)
		(connect_pads
			(clearance 0)
		)
		(min_thickness 0.25)
		(keepout
			(tracks not_allowed)
			(vias allowed)
			(pads allowed)
			(copperpour not_allowed)
			(footprints allowed)
		)
		(placement
			(enabled no)
			(sheetname "")
		)
		(fill
			(thermal_gap 0.5)
			(thermal_bridge_width 0.5)
			(island_removal_mode 0)
		)
		(polygon
			(pts
				(arc
					(start 102.023418 -275.08073)
					(mid 102.681278 -275.08073)
					(end 102.023418 -275.08073)
				)
			)
		)
	)
	(zone
		(layers "F.Cu" "B.Cu" "In1.Cu" "In2.Cu" "In3.Cu" "In4.Cu" "In5.Cu" "In6.Cu"
			"In7.Cu" "In8.Cu" "In9.Cu" "In10.Cu" "In11.Cu" "In12.Cu" "In13.Cu" "In14.Cu"
			"In15.Cu" "In16.Cu"
		)
		(hatch none 0.5)
		(connect_pads
			(clearance 0)
		)
		(min_thickness 0.25)
		(keepout
			(tracks not_allowed)
			(vias allowed)
			(pads allowed)
			(copperpour not_allowed)
			(footprints allowed)
		)
		(placement
			(enabled no)
			(sheetname "")
		)
		(fill
			(thermal_gap 0.5)
			(thermal_bridge_width 0.5)
			(island_removal_mode 0)
		)
		(polygon
			(pts
				(arc
					(start 130.295396 -213.732618)
					(mid 129.637536 -213.732618)
					(end 130.295396 -213.732618)
				)
			)
		)
	)
	(zone
		(layers "F.Cu" "B.Cu" "In1.Cu" "In2.Cu" "In3.Cu" "In4.Cu" "In5.Cu" "In6.Cu"
			"In7.Cu" "In8.Cu" "In9.Cu" "In10.Cu" "In11.Cu" "In12.Cu" "In13.Cu" "In14.Cu"
			"In15.Cu" "In16.Cu"
		)
		(hatch none 0.5)
		(connect_pads
			(clearance 0)
		)
		(min_thickness 0.25)
		(keepout
			(tracks not_allowed)
			(vias allowed)
			(pads allowed)
			(copperpour not_allowed)
			(footprints allowed)
		)
		(placement
			(enabled no)
			(sheetname "")
		)
		(fill
			(thermal_gap 0.5)
			(thermal_bridge_width 0.5)
			(island_removal_mode 0)
		)
		(polygon
			(pts
				(arc
					(start 99.673918 -288.917126)
					(mid 100.331778 -288.917126)
					(end 99.673918 -288.917126)
				)
			)
		)
	)
	(zone
		(layers "F.Cu" "B.Cu" "In1.Cu" "In2.Cu" "In3.Cu" "In4.Cu" "In5.Cu" "In6.Cu"
			"In7.Cu" "In8.Cu" "In9.Cu" "In10.Cu" "In11.Cu" "In12.Cu" "In13.Cu" "In14.Cu"
			"In15.Cu" "In16.Cu"
		)
		(hatch none 0.5)
		(connect_pads
			(clearance 0)
		)
		(min_thickness 0.25)
		(keepout
			(tracks not_allowed)
			(vias allowed)
			(pads allowed)
			(copperpour not_allowed)
			(footprints allowed)
		)
		(placement
			(enabled no)
			(sheetname "")
		)
		(fill
			(thermal_gap 0.5)
			(thermal_bridge_width 0.5)
			(island_removal_mode 0)
		)
		(polygon
			(pts
				(arc
					(start 93.924882 -220.319854)
					(mid 94.582742 -220.319854)
					(end 93.924882 -220.319854)
				)
			)
		)
	)
	(zone
		(layers "F.Cu" "B.Cu" "In1.Cu" "In2.Cu" "In3.Cu" "In4.Cu" "In5.Cu" "In6.Cu"
			"In7.Cu" "In8.Cu" "In9.Cu" "In10.Cu" "In11.Cu" "In12.Cu" "In13.Cu" "In14.Cu"
			"In15.Cu" "In16.Cu"
		)
		(hatch none 0.5)
		(connect_pads
			(clearance 0)
		)
		(min_thickness 0.25)
		(keepout
			(tracks not_allowed)
			(vias allowed)
			(pads allowed)
			(copperpour not_allowed)
			(footprints allowed)
		)
		(placement
			(enabled no)
			(sheetname "")
		)
		(fill
			(thermal_gap 0.5)
			(thermal_bridge_width 0.5)
			(island_removal_mode 0)
		)
		(polygon
			(pts
				(arc
					(start 338.293964 -221.133924)
					(mid 337.636104 -221.133924)
					(end 338.293964 -221.133924)
				)
			)
		)
	)
	(zone
		(layers "F.Cu" "B.Cu" "In1.Cu" "In2.Cu" "In3.Cu" "In4.Cu" "In5.Cu" "In6.Cu"
			"In7.Cu" "In8.Cu" "In9.Cu" "In10.Cu" "In11.Cu" "In12.Cu" "In13.Cu" "In14.Cu"
			"In15.Cu" "In16.Cu"
		)
		(hatch none 0.5)
		(connect_pads
			(clearance 0)
		)
		(min_thickness 0.25)
		(keepout
			(tracks not_allowed)
			(vias allowed)
			(pads allowed)
			(copperpour not_allowed)
			(footprints allowed)
		)
		(placement
			(enabled no)
			(sheetname "")
		)
		(fill
			(thermal_gap 0.5)
			(thermal_bridge_width 0.5)
			(island_removal_mode 0)
		)
		(polygon
			(pts
				(arc
					(start 96.384618 -279.964134)
					(mid 97.042478 -279.964134)
					(end 96.384618 -279.964134)
				)
			)
		)
	)
	(zone
		(layers "F.Cu" "B.Cu" "In1.Cu" "In2.Cu" "In3.Cu" "In4.Cu" "In5.Cu" "In6.Cu"
			"In7.Cu" "In8.Cu" "In9.Cu" "In10.Cu" "In11.Cu" "In12.Cu" "In13.Cu" "In14.Cu"
			"In15.Cu" "In16.Cu"
		)
		(hatch none 0.5)
		(connect_pads
			(clearance 0)
		)
		(min_thickness 0.25)
		(keepout
			(tracks not_allowed)
			(vias allowed)
			(pads allowed)
			(copperpour not_allowed)
			(footprints allowed)
		)
		(placement
			(enabled no)
			(sheetname "")
		)
		(fill
			(thermal_gap 0.5)
			(thermal_bridge_width 0.5)
			(island_removal_mode 0)
		)
		(polygon
			(pts
				(arc
					(start 378.17933 -289.003232)
					(mid 378.195254 -288.961481)
					(end 378.200666 -288.917126)
				)
				(arc
					(start 378.200666 -288.917126)
					(mid 378.14673 -288.786912)
					(end 378.016516 -288.732976)
				)
				(arc
					(start 378.016516 -288.732976)
					(mid 377.921496 -288.759384)
					(end 377.853702 -288.83102)
				)
				(arc
					(start 377.383548 -289.721036)
					(mid 377.367624 -289.762787)
					(end 377.362212 -289.807142)
				)
				(arc
					(start 377.362212 -289.807142)
					(mid 377.416148 -289.937356)
					(end 377.546362 -289.991292)
				)
				(arc
					(start 377.546362 -289.991292)
					(mid 377.641382 -289.964884)
					(end 377.709176 -289.893248)
				)
			)
		)
	)
	(zone
		(layers "F.Cu" "B.Cu" "In1.Cu" "In2.Cu" "In3.Cu" "In4.Cu" "In5.Cu" "In6.Cu"
			"In7.Cu" "In8.Cu" "In9.Cu" "In10.Cu" "In11.Cu" "In12.Cu" "In13.Cu" "In14.Cu"
			"In15.Cu" "In16.Cu"
		)
		(hatch none 0.5)
		(connect_pads
			(clearance 0)
		)
		(min_thickness 0.25)
		(keepout
			(tracks not_allowed)
			(vias allowed)
			(pads allowed)
			(copperpour not_allowed)
			(footprints allowed)
		)
		(placement
			(enabled no)
			(sheetname "")
		)
		(fill
			(thermal_gap 0.5)
			(thermal_bridge_width 0.5)
			(island_removal_mode 0)
		)
		(polygon
			(pts
				(arc
					(start 96.303846 -220.418152)
					(mid 96.32353 -220.370742)
					(end 96.330262 -220.319854)
				)
				(arc
					(start 96.330262 -220.319854)
					(mid 96.272606 -220.18066)
					(end 96.133412 -220.123004)
				)
				(arc
					(start 96.133412 -220.123004)
					(mid 96.034981 -220.14942)
					(end 95.962978 -220.221556)
				)
				(arc
					(start 95.493332 -221.035626)
					(mid 95.473648 -221.083036)
					(end 95.466916 -221.133924)
				)
				(arc
					(start 95.466916 -221.133924)
					(mid 95.524572 -221.273118)
					(end 95.663766 -221.330774)
				)
				(arc
					(start 95.663766 -221.330774)
					(mid 95.762197 -221.304358)
					(end 95.8342 -221.232222)
				)
			)
		)
	)
	(zone
		(layers "F.Cu" "B.Cu" "In1.Cu" "In2.Cu" "In3.Cu" "In4.Cu" "In5.Cu" "In6.Cu"
			"In7.Cu" "In8.Cu" "In9.Cu" "In10.Cu" "In11.Cu" "In12.Cu" "In13.Cu" "In14.Cu"
			"In15.Cu" "In16.Cu"
		)
		(hatch none 0.5)
		(connect_pads
			(clearance 0)
		)
		(min_thickness 0.25)
		(keepout
			(tracks not_allowed)
			(vias allowed)
			(pads allowed)
			(copperpour not_allowed)
			(footprints allowed)
		)
		(placement
			(enabled no)
			(sheetname "")
		)
		(fill
			(thermal_gap 0.5)
			(thermal_bridge_width 0.5)
			(island_removal_mode 0)
		)
		(polygon
			(pts
				(arc
					(start 142.943834 -406.62352)
					(mid 142.562834 -407.00452)
					(end 142.943834 -407.38552)
				)
				(arc
					(start 143.807434 -407.38552)
					(mid 144.188434 -407.00452)
					(end 143.807434 -406.62352)
				)
			)
		)
	)
	(zone
		(layers "F.Cu" "B.Cu" "In1.Cu" "In2.Cu" "In3.Cu" "In4.Cu" "In5.Cu" "In6.Cu"
			"In7.Cu" "In8.Cu" "In9.Cu" "In10.Cu" "In11.Cu" "In12.Cu" "In13.Cu" "In14.Cu"
			"In15.Cu" "In16.Cu"
		)
		(hatch none 0.5)
		(connect_pads
			(clearance 0)
		)
		(min_thickness 0.25)
		(keepout
			(tracks not_allowed)
			(vias allowed)
			(pads allowed)
			(copperpour not_allowed)
			(footprints allowed)
		)
		(placement
			(enabled no)
			(sheetname "")
		)
		(fill
			(thermal_gap 0.5)
			(thermal_bridge_width 0.5)
			(island_removal_mode 0)
		)
		(polygon
			(pts
				(arc
					(start 349.652082 -288.818828)
					(mid 349.632398 -288.866238)
					(end 349.625666 -288.917126)
				)
				(arc
					(start 349.625666 -288.917126)
					(mid 349.683322 -289.05632)
					(end 349.822516 -289.113976)
				)
				(arc
					(start 349.822516 -289.113976)
					(mid 349.920947 -289.08756)
					(end 349.99295 -289.015424)
				)
				(arc
					(start 350.46285 -288.201354)
					(mid 350.482534 -288.153944)
					(end 350.489266 -288.103056)
				)
				(arc
					(start 350.489266 -288.103056)
					(mid 350.43161 -287.963862)
					(end 350.292416 -287.906206)
				)
				(arc
					(start 350.292416 -287.906206)
					(mid 350.193985 -287.932622)
					(end 350.121982 -288.004758)
				)
			)
		)
	)
	(zone
		(layers "F.Cu" "B.Cu" "In1.Cu" "In2.Cu" "In3.Cu" "In4.Cu" "In5.Cu" "In6.Cu"
			"In7.Cu" "In8.Cu" "In9.Cu" "In10.Cu" "In11.Cu" "In12.Cu" "In13.Cu" "In14.Cu"
			"In15.Cu" "In16.Cu"
		)
		(hatch none 0.5)
		(connect_pads
			(clearance 0)
		)
		(min_thickness 0.25)
		(keepout
			(tracks not_allowed)
			(vias allowed)
			(pads allowed)
			(copperpour not_allowed)
			(footprints allowed)
		)
		(placement
			(enabled no)
			(sheetname "")
		)
		(fill
			(thermal_gap 0.5)
			(thermal_bridge_width 0.5)
			(island_removal_mode 0)
		)
		(polygon
			(pts
				(arc
					(start 102.493064 -275.8948)
					(mid 103.150924 -275.8948)
					(end 102.493064 -275.8948)
				)
			)
		)
	)
	(zone
		(layers "F.Cu" "B.Cu" "In1.Cu" "In2.Cu" "In3.Cu" "In4.Cu" "In5.Cu" "In6.Cu"
			"In7.Cu" "In8.Cu" "In9.Cu" "In10.Cu" "In11.Cu" "In12.Cu" "In13.Cu" "In14.Cu"
			"In15.Cu" "In16.Cu"
		)
		(hatch none 0.5)
		(connect_pads
			(clearance 0)
		)
		(min_thickness 0.25)
		(keepout
			(tracks not_allowed)
			(vias allowed)
			(pads allowed)
			(copperpour not_allowed)
			(footprints allowed)
		)
		(placement
			(enabled no)
			(sheetname "")
		)
		(fill
			(thermal_gap 0.5)
			(thermal_bridge_width 0.5)
			(island_removal_mode 0)
		)
		(polygon
			(pts
				(arc
					(start 107.082082 -220.319854)
					(mid 107.739942 -220.319854)
					(end 107.082082 -220.319854)
				)
			)
		)
	)
	(zone
		(layers "F.Cu" "B.Cu" "In1.Cu" "In2.Cu" "In3.Cu" "In4.Cu" "In5.Cu" "In6.Cu"
			"In7.Cu" "In8.Cu" "In9.Cu" "In10.Cu" "In11.Cu" "In12.Cu" "In13.Cu" "In14.Cu"
			"In15.Cu" "In16.Cu"
		)
		(hatch none 0.5)
		(connect_pads
			(clearance 0)
		)
		(min_thickness 0.25)
		(keepout
			(tracks not_allowed)
			(vias allowed)
			(pads allowed)
			(copperpour not_allowed)
			(footprints allowed)
		)
		(placement
			(enabled no)
			(sheetname "")
		)
		(fill
			(thermal_gap 0.5)
			(thermal_bridge_width 0.5)
			(island_removal_mode 0)
		)
		(polygon
			(pts
				(arc
					(start 103.432864 -274.266914)
					(mid 104.090724 -274.266914)
					(end 103.432864 -274.266914)
				)
			)
		)
	)
	(zone
		(layers "F.Cu" "B.Cu" "In1.Cu" "In2.Cu" "In3.Cu" "In4.Cu" "In5.Cu" "In6.Cu"
			"In7.Cu" "In8.Cu" "In9.Cu" "In10.Cu" "In11.Cu" "In12.Cu" "In13.Cu" "In14.Cu"
			"In15.Cu" "In16.Cu"
		)
		(hatch none 0.5)
		(connect_pads
			(clearance 0)
		)
		(min_thickness 0.25)
		(keepout
			(tracks not_allowed)
			(vias allowed)
			(pads allowed)
			(copperpour not_allowed)
			(footprints allowed)
		)
		(placement
			(enabled no)
			(sheetname "")
		)
		(fill
			(thermal_gap 0.5)
			(thermal_bridge_width 0.5)
			(island_removal_mode 0)
		)
		(polygon
			(pts
				(arc
					(start 342.834468 -224.291144)
					(mid 342.762479 -224.218985)
					(end 342.664034 -224.192592)
				)
				(arc
					(start 342.664034 -224.192592)
					(mid 342.52484 -224.250248)
					(end 342.467184 -224.389442)
				)
				(arc
					(start 342.467184 -224.389442)
					(mid 342.473941 -224.440323)
					(end 342.4936 -224.48774)
				)
				(arc
					(start 342.963246 -225.301556)
					(mid 343.035235 -225.373715)
					(end 343.13368 -225.400108)
				)
				(arc
					(start 343.13368 -225.400108)
					(mid 343.272874 -225.342452)
					(end 343.33053 -225.203258)
				)
				(arc
					(start 343.33053 -225.203258)
					(mid 343.323773 -225.152377)
					(end 343.304114 -225.10496)
				)
			)
		)
	)
	(zone
		(layers "F.Cu" "B.Cu" "In1.Cu" "In2.Cu" "In3.Cu" "In4.Cu" "In5.Cu" "In6.Cu"
			"In7.Cu" "In8.Cu" "In9.Cu" "In10.Cu" "In11.Cu" "In12.Cu" "In13.Cu" "In14.Cu"
			"In15.Cu" "In16.Cu"
		)
		(hatch none 0.5)
		(connect_pads
			(clearance 0)
		)
		(min_thickness 0.25)
		(keepout
			(tracks not_allowed)
			(vias allowed)
			(pads allowed)
			(copperpour not_allowed)
			(footprints allowed)
		)
		(placement
			(enabled no)
			(sheetname "")
		)
		(fill
			(thermal_gap 0.5)
			(thermal_bridge_width 0.5)
			(island_removal_mode 0)
		)
		(polygon
			(pts
				(arc
					(start 22.673056 -382.552194)
					(mid 22.292056 -382.933194)
					(end 22.673056 -383.314194)
				)
				(arc
					(start 23.536656 -383.314194)
					(mid 23.917656 -382.933194)
					(end 23.536656 -382.552194)
				)
			)
		)
	)
	(zone
		(layers "F.Cu" "B.Cu" "In1.Cu" "In2.Cu" "In3.Cu" "In4.Cu" "In5.Cu" "In6.Cu"
			"In7.Cu" "In8.Cu" "In9.Cu" "In10.Cu" "In11.Cu" "In12.Cu" "In13.Cu" "In14.Cu"
			"In15.Cu" "In16.Cu"
		)
		(hatch none 0.5)
		(connect_pads
			(clearance 0)
		)
		(min_thickness 0.25)
		(keepout
			(tracks not_allowed)
			(vias allowed)
			(pads allowed)
			(copperpour not_allowed)
			(footprints allowed)
		)
		(placement
			(enabled no)
			(sheetname "")
		)
		(fill
			(thermal_gap 0.5)
			(thermal_bridge_width 0.5)
			(island_removal_mode 0)
		)
		(polygon
			(pts
				(arc
					(start 378.077222 -216.966292)
					(mid 378.005233 -216.894133)
					(end 377.906788 -216.86774)
				)
				(arc
					(start 377.906788 -216.86774)
					(mid 377.767594 -216.925396)
					(end 377.709938 -217.06459)
				)
				(arc
					(start 377.709938 -217.06459)
					(mid 377.716695 -217.115471)
					(end 377.736354 -217.162888)
				)
				(arc
					(start 378.206 -217.976704)
					(mid 378.277989 -218.048863)
					(end 378.376434 -218.075256)
				)
				(arc
					(start 378.376434 -218.075256)
					(mid 378.515628 -218.0176)
					(end 378.573284 -217.878406)
				)
				(arc
					(start 378.573284 -217.878406)
					(mid 378.566527 -217.827525)
					(end 378.546868 -217.780108)
				)
			)
		)
	)
	(zone
		(layers "F.Cu" "B.Cu" "In1.Cu" "In2.Cu" "In3.Cu" "In4.Cu" "In5.Cu" "In6.Cu"
			"In7.Cu" "In8.Cu" "In9.Cu" "In10.Cu" "In11.Cu" "In12.Cu" "In13.Cu" "In14.Cu"
			"In15.Cu" "In16.Cu"
		)
		(hatch none 0.5)
		(connect_pads
			(clearance 0)
		)
		(min_thickness 0.25)
		(keepout
			(tracks not_allowed)
			(vias allowed)
			(pads allowed)
			(copperpour not_allowed)
			(footprints allowed)
		)
		(placement
			(enabled no)
			(sheetname "")
		)
		(fill
			(thermal_gap 0.5)
			(thermal_bridge_width 0.5)
			(island_removal_mode 0)
		)
		(polygon
			(pts
				(arc
					(start 364.13821 -221.94774)
					(mid 363.48035 -221.94774)
					(end 364.13821 -221.94774)
				)
			)
		)
	)
	(zone
		(layers "F.Cu" "B.Cu" "In1.Cu" "In2.Cu" "In3.Cu" "In4.Cu" "In5.Cu" "In6.Cu"
			"In7.Cu" "In8.Cu" "In9.Cu" "In10.Cu" "In11.Cu" "In12.Cu" "In13.Cu" "In14.Cu"
			"In15.Cu" "In16.Cu"
		)
		(hatch none 0.5)
		(connect_pads
			(clearance 0)
		)
		(min_thickness 0.25)
		(keepout
			(tracks not_allowed)
			(vias allowed)
			(pads allowed)
			(copperpour not_allowed)
			(footprints allowed)
		)
		(placement
			(enabled no)
			(sheetname "")
		)
		(fill
			(thermal_gap 0.5)
			(thermal_bridge_width 0.5)
			(island_removal_mode 0)
		)
		(polygon
			(pts
				(arc
					(start 346.593668 -221.035626)
					(mid 346.521679 -220.963467)
					(end 346.423234 -220.937074)
				)
				(arc
					(start 346.423234 -220.937074)
					(mid 346.28404 -220.99473)
					(end 346.226384 -221.133924)
				)
				(arc
					(start 346.226384 -221.133924)
					(mid 346.233141 -221.184805)
					(end 346.2528 -221.232222)
				)
				(arc
					(start 346.722446 -222.046038)
					(mid 346.794435 -222.118197)
					(end 346.89288 -222.14459)
				)
				(arc
					(start 346.89288 -222.14459)
					(mid 347.032074 -222.086934)
					(end 347.08973 -221.94774)
				)
				(arc
					(start 347.08973 -221.94774)
					(mid 347.082973 -221.896859)
					(end 347.063314 -221.849442)
				)
			)
		)
	)
	(zone
		(layers "F.Cu" "B.Cu" "In1.Cu" "In2.Cu" "In3.Cu" "In4.Cu" "In5.Cu" "In6.Cu"
			"In7.Cu" "In8.Cu" "In9.Cu" "In10.Cu" "In11.Cu" "In12.Cu" "In13.Cu" "In14.Cu"
			"In15.Cu" "In16.Cu"
		)
		(hatch none 0.5)
		(connect_pads
			(clearance 0)
		)
		(min_thickness 0.25)
		(keepout
			(tracks not_allowed)
			(vias allowed)
			(pads allowed)
			(copperpour not_allowed)
			(footprints allowed)
		)
		(placement
			(enabled no)
			(sheetname "")
		)
		(fill
			(thermal_gap 0.5)
			(thermal_bridge_width 0.5)
			(island_removal_mode 0)
		)
		(polygon
			(pts
				(arc
					(start 131.546092 -214.720932)
					(mid 131.565776 -214.673522)
					(end 131.572508 -214.622634)
				)
				(arc
					(start 131.572508 -214.622634)
					(mid 131.514852 -214.48344)
					(end 131.375658 -214.425784)
				)
				(arc
					(start 131.375658 -214.425784)
					(mid 131.277227 -214.4522)
					(end 131.205224 -214.524336)
				)
				(arc
					(start 130.735578 -215.338406)
					(mid 130.715894 -215.385816)
					(end 130.709162 -215.436704)
				)
				(arc
					(start 130.709162 -215.436704)
					(mid 130.766818 -215.575898)
					(end 130.906012 -215.633554)
				)
				(arc
					(start 130.906012 -215.633554)
					(mid 131.004443 -215.607138)
					(end 131.076446 -215.535002)
				)
			)
		)
	)
	(zone
		(layers "F.Cu" "B.Cu" "In1.Cu" "In2.Cu" "In3.Cu" "In4.Cu" "In5.Cu" "In6.Cu"
			"In7.Cu" "In8.Cu" "In9.Cu" "In10.Cu" "In11.Cu" "In12.Cu" "In13.Cu" "In14.Cu"
			"In15.Cu" "In16.Cu"
		)
		(hatch none 0.5)
		(connect_pads
			(clearance 0)
		)
		(min_thickness 0.25)
		(keepout
			(tracks not_allowed)
			(vias allowed)
			(pads allowed)
			(copperpour not_allowed)
			(footprints allowed)
		)
		(placement
			(enabled no)
			(sheetname "")
		)
		(fill
			(thermal_gap 0.5)
			(thermal_bridge_width 0.5)
			(island_removal_mode 0)
		)
		(polygon
			(pts
				(arc
					(start 50.136806 -6.343396)
					(mid 49.755806 -6.724396)
					(end 50.136806 -7.105396)
				)
				(arc
					(start 51.000406 -7.105396)
					(mid 51.381406 -6.724396)
					(end 51.000406 -6.343396)
				)
			)
		)
	)
	(zone
		(layers "F.Cu" "B.Cu" "In1.Cu" "In2.Cu" "In3.Cu" "In4.Cu" "In5.Cu" "In6.Cu"
			"In7.Cu" "In8.Cu" "In9.Cu" "In10.Cu" "In11.Cu" "In12.Cu" "In13.Cu" "In14.Cu"
			"In15.Cu" "In16.Cu"
		)
		(hatch none 0.5)
		(connect_pads
			(clearance 0)
		)
		(min_thickness 0.25)
		(keepout
			(tracks not_allowed)
			(vias allowed)
			(pads allowed)
			(copperpour not_allowed)
			(footprints allowed)
		)
		(placement
			(enabled no)
			(sheetname "")
		)
		(fill
			(thermal_gap 0.5)
			(thermal_bridge_width 0.5)
			(island_removal_mode 0)
		)
		(polygon
			(pts
				(arc
					(start 64.642238 -409.649168)
					(mid 64.261238 -410.030168)
					(end 64.642238 -410.411168)
				)
				(arc
					(start 65.505838 -410.411168)
					(mid 65.886838 -410.030168)
					(end 65.505838 -409.649168)
				)
			)
		)
	)
	(zone
		(layers "F.Cu" "B.Cu" "In1.Cu" "In2.Cu" "In3.Cu" "In4.Cu" "In5.Cu" "In6.Cu"
			"In7.Cu" "In8.Cu" "In9.Cu" "In10.Cu" "In11.Cu" "In12.Cu" "In13.Cu" "In14.Cu"
			"In15.Cu" "In16.Cu"
		)
		(hatch none 0.5)
		(connect_pads
			(clearance 0)
		)
		(min_thickness 0.25)
		(keepout
			(tracks not_allowed)
			(vias allowed)
			(pads allowed)
			(copperpour not_allowed)
			(footprints allowed)
		)
		(placement
			(enabled no)
			(sheetname "")
		)
		(fill
			(thermal_gap 0.5)
			(thermal_bridge_width 0.5)
			(island_removal_mode 0)
		)
		(polygon
			(pts
				(arc
					(start 78.612238 -403.502876)
					(mid 78.231238 -403.883876)
					(end 78.612238 -404.264876)
				)
				(arc
					(start 79.475838 -404.264876)
					(mid 79.856838 -403.883876)
					(end 79.475838 -403.502876)
				)
			)
		)
	)
	(zone
		(layers "F.Cu" "B.Cu" "In1.Cu" "In2.Cu" "In3.Cu" "In4.Cu" "In5.Cu" "In6.Cu"
			"In7.Cu" "In8.Cu" "In9.Cu" "In10.Cu" "In11.Cu" "In12.Cu" "In13.Cu" "In14.Cu"
			"In15.Cu" "In16.Cu"
		)
		(hatch none 0.5)
		(connect_pads
			(clearance 0)
		)
		(min_thickness 0.25)
		(keepout
			(tracks not_allowed)
			(vias allowed)
			(pads allowed)
			(copperpour not_allowed)
			(footprints allowed)
		)
		(placement
			(enabled no)
			(sheetname "")
		)
		(fill
			(thermal_gap 0.5)
			(thermal_bridge_width 0.5)
			(island_removal_mode 0)
		)
		(polygon
			(pts
				(arc
					(start 179.39258 -45.618146)
					(mid 179.01158 -45.237146)
					(end 178.63058 -45.618146)
				)
				(arc
					(start 178.63058 -46.481746)
					(mid 179.01158 -46.862746)
					(end 179.39258 -46.481746)
				)
			)
		)
	)
	(zone
		(layers "F.Cu" "B.Cu" "In1.Cu" "In2.Cu" "In3.Cu" "In4.Cu" "In5.Cu" "In6.Cu"
			"In7.Cu" "In8.Cu" "In9.Cu" "In10.Cu" "In11.Cu" "In12.Cu" "In13.Cu" "In14.Cu"
			"In15.Cu" "In16.Cu"
		)
		(hatch none 0.5)
		(connect_pads
			(clearance 0)
		)
		(min_thickness 0.25)
		(keepout
			(tracks not_allowed)
			(vias allowed)
			(pads allowed)
			(copperpour not_allowed)
			(footprints allowed)
		)
		(placement
			(enabled no)
			(sheetname "")
		)
		(fill
			(thermal_gap 0.5)
			(thermal_bridge_width 0.5)
			(island_removal_mode 0)
		)
		(polygon
			(pts
				(arc
					(start 367.89741 -218.692222)
					(mid 367.23955 -218.692222)
					(end 367.89741 -218.692222)
				)
			)
		)
	)
	(zone
		(layers "F.Cu" "B.Cu" "In1.Cu" "In2.Cu" "In3.Cu" "In4.Cu" "In5.Cu" "In6.Cu"
			"In7.Cu" "In8.Cu" "In9.Cu" "In10.Cu" "In11.Cu" "In12.Cu" "In13.Cu" "In14.Cu"
			"In15.Cu" "In16.Cu"
		)
		(hatch none 0.5)
		(connect_pads
			(clearance 0)
		)
		(min_thickness 0.25)
		(keepout
			(tracks not_allowed)
			(vias allowed)
			(pads allowed)
			(copperpour not_allowed)
			(footprints allowed)
		)
		(placement
			(enabled no)
			(sheetname "")
		)
		(fill
			(thermal_gap 0.5)
			(thermal_bridge_width 0.5)
			(island_removal_mode 0)
		)
		(polygon
			(pts
				(arc
					(start 373.066564 -221.133924)
					(mid 372.408704 -221.133924)
					(end 373.066564 -221.133924)
				)
			)
		)
	)
	(zone
		(layers "F.Cu" "B.Cu" "In1.Cu" "In2.Cu" "In3.Cu" "In4.Cu" "In5.Cu" "In6.Cu"
			"In7.Cu" "In8.Cu" "In9.Cu" "In10.Cu" "In11.Cu" "In12.Cu" "In13.Cu" "In14.Cu"
			"In15.Cu" "In16.Cu"
		)
		(hatch none 0.5)
		(connect_pads
			(clearance 0)
		)
		(min_thickness 0.25)
		(keepout
			(tracks not_allowed)
			(vias allowed)
			(pads allowed)
			(copperpour not_allowed)
			(footprints allowed)
		)
		(placement
			(enabled no)
			(sheetname "")
		)
		(fill
			(thermal_gap 0.5)
			(thermal_bridge_width 0.5)
			(island_removal_mode 0)
		)
		(polygon
			(pts
				(arc
					(start 97.794064 -282.405836)
					(mid 98.451924 -282.405836)
					(end 97.794064 -282.405836)
				)
			)
		)
	)
	(zone
		(layers "F.Cu" "B.Cu" "In1.Cu" "In2.Cu" "In3.Cu" "In4.Cu" "In5.Cu" "In6.Cu"
			"In7.Cu" "In8.Cu" "In9.Cu" "In10.Cu" "In11.Cu" "In12.Cu" "In13.Cu" "In14.Cu"
			"In15.Cu" "In16.Cu"
		)
		(hatch none 0.5)
		(connect_pads
			(clearance 0)
		)
		(min_thickness 0.25)
		(keepout
			(tracks not_allowed)
			(vias allowed)
			(pads allowed)
			(copperpour not_allowed)
			(footprints allowed)
		)
		(placement
			(enabled no)
			(sheetname "")
		)
		(fill
			(thermal_gap 0.5)
			(thermal_bridge_width 0.5)
			(island_removal_mode 0)
		)
		(polygon
			(pts
				(arc
					(start 371.96776 -221.231968)
					(mid 371.987444 -221.184558)
					(end 371.994176 -221.13367)
				)
				(arc
					(start 371.994176 -221.13367)
					(mid 371.93652 -220.994476)
					(end 371.797326 -220.93682)
				)
				(arc
					(start 371.797326 -220.93682)
					(mid 371.698895 -220.963236)
					(end 371.626892 -221.035372)
				)
				(arc
					(start 371.157246 -221.849442)
					(mid 371.137562 -221.896852)
					(end 371.13083 -221.94774)
				)
				(arc
					(start 371.13083 -221.94774)
					(mid 371.188486 -222.086934)
					(end 371.32768 -222.14459)
				)
				(arc
					(start 371.32768 -222.14459)
					(mid 371.426111 -222.118174)
					(end 371.498114 -222.046038)
				)
			)
		)
	)
	(zone
		(layers "F.Cu" "B.Cu" "In1.Cu" "In2.Cu" "In3.Cu" "In4.Cu" "In5.Cu" "In6.Cu"
			"In7.Cu" "In8.Cu" "In9.Cu" "In10.Cu" "In11.Cu" "In12.Cu" "In13.Cu" "In14.Cu"
			"In15.Cu" "In16.Cu"
		)
		(hatch none 0.5)
		(connect_pads
			(clearance 0)
		)
		(min_thickness 0.25)
		(keepout
			(tracks not_allowed)
			(vias allowed)
			(pads allowed)
			(copperpour not_allowed)
			(footprints allowed)
		)
		(placement
			(enabled no)
			(sheetname "")
		)
		(fill
			(thermal_gap 0.5)
			(thermal_bridge_width 0.5)
			(island_removal_mode 0)
		)
		(polygon
			(pts
				(arc
					(start 360.69016 -217.97645)
					(mid 360.709844 -217.92904)
					(end 360.716576 -217.878152)
				)
				(arc
					(start 360.716576 -217.878152)
					(mid 360.65892 -217.738958)
					(end 360.519726 -217.681302)
				)
				(arc
					(start 360.519726 -217.681302)
					(mid 360.421295 -217.707718)
					(end 360.349292 -217.779854)
				)
				(arc
					(start 359.879646 -218.593924)
					(mid 359.859962 -218.641334)
					(end 359.85323 -218.692222)
				)
				(arc
					(start 359.85323 -218.692222)
					(mid 359.910886 -218.831416)
					(end 360.05008 -218.889072)
				)
				(arc
					(start 360.05008 -218.889072)
					(mid 360.148511 -218.862656)
					(end 360.220514 -218.79052)
				)
			)
		)
	)
	(zone
		(layers "F.Cu" "B.Cu" "In1.Cu" "In2.Cu" "In3.Cu" "In4.Cu" "In5.Cu" "In6.Cu"
			"In7.Cu" "In8.Cu" "In9.Cu" "In10.Cu" "In11.Cu" "In12.Cu" "In13.Cu" "In14.Cu"
			"In15.Cu" "In16.Cu"
		)
		(hatch none 0.5)
		(connect_pads
			(clearance 0)
		)
		(min_thickness 0.25)
		(keepout
			(tracks not_allowed)
			(vias allowed)
			(pads allowed)
			(copperpour not_allowed)
			(footprints allowed)
		)
		(placement
			(enabled no)
			(sheetname "")
		)
		(fill
			(thermal_gap 0.5)
			(thermal_bridge_width 0.5)
			(island_removal_mode 0)
		)
		(polygon
			(pts
				(arc
					(start 378.077222 -220.22181)
					(mid 378.005233 -220.149651)
					(end 377.906788 -220.123258)
				)
				(arc
					(start 377.906788 -220.123258)
					(mid 377.767594 -220.180914)
					(end 377.709938 -220.320108)
				)
				(arc
					(start 377.709938 -220.320108)
					(mid 377.716695 -220.370989)
					(end 377.736354 -220.418406)
				)
				(arc
					(start 378.206 -221.232222)
					(mid 378.277989 -221.304381)
					(end 378.376434 -221.330774)
				)
				(arc
					(start 378.376434 -221.330774)
					(mid 378.515628 -221.273118)
					(end 378.573284 -221.133924)
				)
				(arc
					(start 378.573284 -221.133924)
					(mid 378.566527 -221.083043)
					(end 378.546868 -221.035626)
				)
			)
		)
	)
	(zone
		(layers "F.Cu" "B.Cu" "In1.Cu" "In2.Cu" "In3.Cu" "In4.Cu" "In5.Cu" "In6.Cu"
			"In7.Cu" "In8.Cu" "In9.Cu" "In10.Cu" "In11.Cu" "In12.Cu" "In13.Cu" "In14.Cu"
			"In15.Cu" "In16.Cu"
		)
		(hatch none 0.5)
		(connect_pads
			(clearance 0)
		)
		(min_thickness 0.25)
		(keepout
			(tracks not_allowed)
			(vias allowed)
			(pads allowed)
			(copperpour not_allowed)
			(footprints allowed)
		)
		(placement
			(enabled no)
			(sheetname "")
		)
		(fill
			(thermal_gap 0.5)
			(thermal_bridge_width 0.5)
			(island_removal_mode 0)
		)
		(polygon
			(pts
				(arc
					(start 133.754114 -409.649168)
					(mid 133.373114 -410.030168)
					(end 133.754114 -410.411168)
				)
				(arc
					(start 134.617714 -410.411168)
					(mid 134.998714 -410.030168)
					(end 134.617714 -409.649168)
				)
			)
		)
	)
	(zone
		(layers "F.Cu" "B.Cu" "In1.Cu" "In2.Cu" "In3.Cu" "In4.Cu" "In5.Cu" "In6.Cu"
			"In7.Cu" "In8.Cu" "In9.Cu" "In10.Cu" "In11.Cu" "In12.Cu" "In13.Cu" "In14.Cu"
			"In15.Cu" "In16.Cu"
		)
		(hatch none 0.5)
		(connect_pads
			(clearance 0)
		)
		(min_thickness 0.25)
		(keepout
			(tracks not_allowed)
			(vias allowed)
			(pads allowed)
			(copperpour not_allowed)
			(footprints allowed)
		)
		(placement
			(enabled no)
			(sheetname "")
		)
		(fill
			(thermal_gap 0.5)
			(thermal_bridge_width 0.5)
			(island_removal_mode 0)
		)
		(polygon
			(pts
				(arc
					(start 400.724116 -6.332474)
					(mid 400.343116 -6.713474)
					(end 400.724116 -7.094474)
				)
				(arc
					(start 401.587716 -7.094474)
					(mid 401.968716 -6.713474)
					(end 401.587716 -6.332474)
				)
			)
		)
	)
	(zone
		(layers "F.Cu" "B.Cu" "In1.Cu" "In2.Cu" "In3.Cu" "In4.Cu" "In5.Cu" "In6.Cu"
			"In7.Cu" "In8.Cu" "In9.Cu" "In10.Cu" "In11.Cu" "In12.Cu" "In13.Cu" "In14.Cu"
			"In15.Cu" "In16.Cu"
		)
		(hatch none 0.5)
		(connect_pads
			(clearance 0)
		)
		(min_thickness 0.25)
		(keepout
			(tracks not_allowed)
			(vias allowed)
			(pads allowed)
			(copperpour not_allowed)
			(footprints allowed)
		)
		(placement
			(enabled no)
			(sheetname "")
		)
		(fill
			(thermal_gap 0.5)
			(thermal_bridge_width 0.5)
			(island_removal_mode 0)
		)
		(polygon
			(pts
				(arc
					(start 101.741478 -286.475424)
					(mid 101.083618 -286.475424)
					(end 101.741478 -286.475424)
				)
			)
		)
	)
	(zone
		(layers "F.Cu" "B.Cu" "In1.Cu" "In2.Cu" "In3.Cu" "In4.Cu" "In5.Cu" "In6.Cu"
			"In7.Cu" "In8.Cu" "In9.Cu" "In10.Cu" "In11.Cu" "In12.Cu" "In13.Cu" "In14.Cu"
			"In15.Cu" "In16.Cu"
		)
		(hatch none 0.5)
		(connect_pads
			(clearance 0)
		)
		(min_thickness 0.25)
		(keepout
			(tracks not_allowed)
			(vias allowed)
			(pads allowed)
			(copperpour not_allowed)
			(footprints allowed)
		)
		(placement
			(enabled no)
			(sheetname "")
		)
		(fill
			(thermal_gap 0.5)
			(thermal_bridge_width 0.5)
			(island_removal_mode 0)
		)
		(polygon
			(pts
				(arc
					(start 68.142104 -421.760396)
					(mid 68.164422 -421.814278)
					(end 68.218304 -421.836596)
				)
				(arc
					(start 69.158104 -421.836596)
					(mid 69.211986 -421.814278)
					(end 69.234304 -421.760396)
				)
				(arc
					(start 69.234304 -419.218872)
					(mid 69.211986 -419.16499)
					(end 69.158104 -419.142672)
				)
				(arc
					(start 68.218304 -419.142672)
					(mid 68.164422 -419.16499)
					(end 68.142104 -419.218872)
				)
			)
		)
	)
	(zone
		(layers "F.Cu" "B.Cu" "In1.Cu" "In2.Cu" "In3.Cu" "In4.Cu" "In5.Cu" "In6.Cu"
			"In7.Cu" "In8.Cu" "In9.Cu" "In10.Cu" "In11.Cu" "In12.Cu" "In13.Cu" "In14.Cu"
			"In15.Cu" "In16.Cu"
		)
		(hatch none 0.5)
		(connect_pads
			(clearance 0)
		)
		(min_thickness 0.25)
		(keepout
			(tracks not_allowed)
			(vias allowed)
			(pads allowed)
			(copperpour not_allowed)
			(footprints allowed)
		)
		(placement
			(enabled no)
			(sheetname "")
		)
		(fill
			(thermal_gap 0.5)
			(thermal_bridge_width 0.5)
			(island_removal_mode 0)
		)
		(polygon
			(pts
				(arc
					(start 96.102678 -286.475424)
					(mid 95.444818 -286.475424)
					(end 96.102678 -286.475424)
				)
			)
		)
	)
	(zone
		(layers "F.Cu" "B.Cu" "In1.Cu" "In2.Cu" "In3.Cu" "In4.Cu" "In5.Cu" "In6.Cu"
			"In7.Cu" "In8.Cu" "In9.Cu" "In10.Cu" "In11.Cu" "In12.Cu" "In13.Cu" "In14.Cu"
			"In15.Cu" "In16.Cu"
		)
		(hatch none 0.5)
		(connect_pads
			(clearance 0)
		)
		(min_thickness 0.25)
		(keepout
			(tracks not_allowed)
			(vias allowed)
			(pads allowed)
			(copperpour not_allowed)
			(footprints allowed)
		)
		(placement
			(enabled no)
			(sheetname "")
		)
		(fill
			(thermal_gap 0.5)
			(thermal_bridge_width 0.5)
			(island_removal_mode 0)
		)
		(polygon
			(pts
				(arc
					(start 133.896354 -220.22181)
					(mid 133.824365 -220.149651)
					(end 133.72592 -220.123258)
				)
				(arc
					(start 133.72592 -220.123258)
					(mid 133.586726 -220.180914)
					(end 133.52907 -220.320108)
				)
				(arc
					(start 133.52907 -220.320108)
					(mid 133.535827 -220.370989)
					(end 133.555486 -220.418406)
				)
				(arc
					(start 134.025132 -221.232222)
					(mid 134.097121 -221.304381)
					(end 134.195566 -221.330774)
				)
				(arc
					(start 134.195566 -221.330774)
					(mid 134.33476 -221.273118)
					(end 134.392416 -221.133924)
				)
				(arc
					(start 134.392416 -221.133924)
					(mid 134.385659 -221.083043)
					(end 134.366 -221.035626)
				)
			)
		)
	)
	(zone
		(layers "F.Cu" "B.Cu" "In1.Cu" "In2.Cu" "In3.Cu" "In4.Cu" "In5.Cu" "In6.Cu"
			"In7.Cu" "In8.Cu" "In9.Cu" "In10.Cu" "In11.Cu" "In12.Cu" "In13.Cu" "In14.Cu"
			"In15.Cu" "In16.Cu"
		)
		(hatch none 0.5)
		(connect_pads
			(clearance 0)
		)
		(min_thickness 0.25)
		(keepout
			(tracks not_allowed)
			(vias allowed)
			(pads allowed)
			(copperpour not_allowed)
			(footprints allowed)
		)
		(placement
			(enabled no)
			(sheetname "")
		)
		(fill
			(thermal_gap 0.5)
			(thermal_bridge_width 0.5)
			(island_removal_mode 0)
		)
		(polygon
			(pts
				(arc
					(start 376.935746 -284.847538)
					(mid 376.277886 -284.847538)
					(end 376.935746 -284.847538)
				)
			)
		)
	)
	(zone
		(layers "F.Cu" "B.Cu" "In1.Cu" "In2.Cu" "In3.Cu" "In4.Cu" "In5.Cu" "In6.Cu"
			"In7.Cu" "In8.Cu" "In9.Cu" "In10.Cu" "In11.Cu" "In12.Cu" "In13.Cu" "In14.Cu"
			"In15.Cu" "In16.Cu"
		)
		(hatch none 0.5)
		(connect_pads
			(clearance 0)
		)
		(min_thickness 0.25)
		(keepout
			(tracks not_allowed)
			(vias allowed)
			(pads allowed)
			(copperpour not_allowed)
			(footprints allowed)
		)
		(placement
			(enabled no)
			(sheetname "")
		)
		(fill
			(thermal_gap 0.5)
			(thermal_bridge_width 0.5)
			(island_removal_mode 0)
		)
		(polygon
			(pts
				(arc
					(start 92.343224 -281.59202)
					(mid 91.685364 -281.59202)
					(end 92.343224 -281.59202)
				)
			)
		)
	)
	(zone
		(layers "F.Cu" "B.Cu" "In1.Cu" "In2.Cu" "In3.Cu" "In4.Cu" "In5.Cu" "In6.Cu"
			"In7.Cu" "In8.Cu" "In9.Cu" "In10.Cu" "In11.Cu" "In12.Cu" "In13.Cu" "In14.Cu"
			"In15.Cu" "In16.Cu"
		)
		(hatch none 0.5)
		(connect_pads
			(clearance 0)
		)
		(min_thickness 0.25)
		(keepout
			(tracks not_allowed)
			(vias allowed)
			(pads allowed)
			(copperpour not_allowed)
			(footprints allowed)
		)
		(placement
			(enabled no)
			(sheetname "")
		)
		(fill
			(thermal_gap 0.5)
			(thermal_bridge_width 0.5)
			(island_removal_mode 0)
		)
		(polygon
			(pts
				(arc
					(start 97.872296 -224.389442)
					(mid 97.214436 -224.389442)
					(end 97.872296 -224.389442)
				)
			)
		)
	)
	(zone
		(layers "F.Cu" "B.Cu" "In1.Cu" "In2.Cu" "In3.Cu" "In4.Cu" "In5.Cu" "In6.Cu"
			"In7.Cu" "In8.Cu" "In9.Cu" "In10.Cu" "In11.Cu" "In12.Cu" "In13.Cu" "In14.Cu"
			"In15.Cu" "In16.Cu"
		)
		(hatch none 0.5)
		(connect_pads
			(clearance 0)
		)
		(min_thickness 0.25)
		(keepout
			(tracks not_allowed)
			(vias allowed)
			(pads allowed)
			(copperpour not_allowed)
			(footprints allowed)
		)
		(placement
			(enabled no)
			(sheetname "")
		)
		(fill
			(thermal_gap 0.5)
			(thermal_bridge_width 0.5)
			(island_removal_mode 0)
		)
		(polygon
			(pts
				(arc
					(start 116.667788 -214.622634)
					(mid 116.009928 -214.622634)
					(end 116.667788 -214.622634)
				)
			)
		)
	)
	(zone
		(layers "F.Cu" "B.Cu" "In1.Cu" "In2.Cu" "In3.Cu" "In4.Cu" "In5.Cu" "In6.Cu"
			"In7.Cu" "In8.Cu" "In9.Cu" "In10.Cu" "In11.Cu" "In12.Cu" "In13.Cu" "In14.Cu"
			"In15.Cu" "In16.Cu"
		)
		(hatch none 0.5)
		(connect_pads
			(clearance 0)
		)
		(min_thickness 0.25)
		(keepout
			(tracks not_allowed)
			(vias allowed)
			(pads allowed)
			(copperpour not_allowed)
			(footprints allowed)
		)
		(placement
			(enabled no)
			(sheetname "")
		)
		(fill
			(thermal_gap 0.5)
			(thermal_bridge_width 0.5)
			(island_removal_mode 0)
		)
		(polygon
			(pts
				(arc
					(start 97.95256 -285.563056)
					(mid 97.932876 -285.610466)
					(end 97.926144 -285.661354)
				)
				(arc
					(start 97.926144 -285.661354)
					(mid 97.9838 -285.800548)
					(end 98.122994 -285.858204)
				)
				(arc
					(start 98.122994 -285.858204)
					(mid 98.221425 -285.831788)
					(end 98.293428 -285.759652)
				)
				(arc
					(start 98.763328 -284.945582)
					(mid 98.783012 -284.898172)
					(end 98.789744 -284.847284)
				)
				(arc
					(start 98.789744 -284.847284)
					(mid 98.732088 -284.70809)
					(end 98.592894 -284.650434)
				)
				(arc
					(start 98.592894 -284.650434)
					(mid 98.494463 -284.67685)
					(end 98.42246 -284.748986)
				)
			)
		)
	)
	(zone
		(layers "F.Cu" "B.Cu" "In1.Cu" "In2.Cu" "In3.Cu" "In4.Cu" "In5.Cu" "In6.Cu"
			"In7.Cu" "In8.Cu" "In9.Cu" "In10.Cu" "In11.Cu" "In12.Cu" "In13.Cu" "In14.Cu"
			"In15.Cu" "In16.Cu"
		)
		(hatch none 0.5)
		(connect_pads
			(clearance 0)
		)
		(min_thickness 0.25)
		(keepout
			(tracks not_allowed)
			(vias allowed)
			(pads allowed)
			(copperpour not_allowed)
			(footprints allowed)
		)
		(placement
			(enabled no)
			(sheetname "")
		)
		(fill
			(thermal_gap 0.5)
			(thermal_bridge_width 0.5)
			(island_removal_mode 0)
		)
		(polygon
			(pts
				(arc
					(start 337.195668 -217.780108)
					(mid 337.123679 -217.707949)
					(end 337.025234 -217.681556)
				)
				(arc
					(start 337.025234 -217.681556)
					(mid 336.88604 -217.739212)
					(end 336.828384 -217.878406)
				)
				(arc
					(start 336.828384 -217.878406)
					(mid 336.835141 -217.929287)
					(end 336.8548 -217.976704)
				)
				(arc
					(start 337.324446 -218.79052)
					(mid 337.396435 -218.862679)
					(end 337.49488 -218.889072)
				)
				(arc
					(start 337.49488 -218.889072)
					(mid 337.634074 -218.831416)
					(end 337.69173 -218.692222)
				)
				(arc
					(start 337.69173 -218.692222)
					(mid 337.684973 -218.641341)
					(end 337.665314 -218.593924)
				)
			)
		)
	)
	(zone
		(layers "F.Cu" "B.Cu" "In1.Cu" "In2.Cu" "In3.Cu" "In4.Cu" "In5.Cu" "In6.Cu"
			"In7.Cu" "In8.Cu" "In9.Cu" "In10.Cu" "In11.Cu" "In12.Cu" "In13.Cu" "In14.Cu"
			"In15.Cu" "In16.Cu"
		)
		(hatch none 0.5)
		(connect_pads
			(clearance 0)
		)
		(min_thickness 0.25)
		(keepout
			(tracks not_allowed)
			(vias allowed)
			(pads allowed)
			(copperpour not_allowed)
			(footprints allowed)
		)
		(placement
			(enabled no)
			(sheetname "")
		)
		(fill
			(thermal_gap 0.5)
			(thermal_bridge_width 0.5)
			(island_removal_mode 0)
		)
		(polygon
			(pts
				(arc
					(start 243.498624 -57.699402)
					(mid 243.117624 -57.318402)
					(end 242.736624 -57.699402)
				)
				(arc
					(start 242.736624 -58.563002)
					(mid 243.117624 -58.944002)
					(end 243.498624 -58.563002)
				)
			)
		)
	)
	(zone
		(layers "F.Cu" "B.Cu" "In1.Cu" "In2.Cu" "In3.Cu" "In4.Cu" "In5.Cu" "In6.Cu"
			"In7.Cu" "In8.Cu" "In9.Cu" "In10.Cu" "In11.Cu" "In12.Cu" "In13.Cu" "In14.Cu"
			"In15.Cu" "In16.Cu"
		)
		(hatch none 0.5)
		(connect_pads
			(clearance 0)
		)
		(min_thickness 0.25)
		(keepout
			(tracks not_allowed)
			(vias allowed)
			(pads allowed)
			(copperpour not_allowed)
			(footprints allowed)
		)
		(placement
			(enabled no)
			(sheetname "")
		)
		(fill
			(thermal_gap 0.5)
			(thermal_bridge_width 0.5)
			(island_removal_mode 0)
		)
		(polygon
			(pts
				(arc
					(start 49.367694 -17.23136)
					(mid 48.986694 -17.61236)
					(end 49.367694 -17.99336)
				)
				(arc
					(start 50.231294 -17.99336)
					(mid 50.612294 -17.61236)
					(end 50.231294 -17.23136)
				)
			)
		)
	)
	(zone
		(layers "F.Cu" "B.Cu" "In1.Cu" "In2.Cu" "In3.Cu" "In4.Cu" "In5.Cu" "In6.Cu"
			"In7.Cu" "In8.Cu" "In9.Cu" "In10.Cu" "In11.Cu" "In12.Cu" "In13.Cu" "In14.Cu"
			"In15.Cu" "In16.Cu"
		)
		(hatch none 0.5)
		(connect_pads
			(clearance 0)
		)
		(min_thickness 0.25)
		(keepout
			(tracks not_allowed)
			(vias allowed)
			(pads allowed)
			(copperpour not_allowed)
			(footprints allowed)
		)
		(placement
			(enabled no)
			(sheetname "")
		)
		(fill
			(thermal_gap 0.5)
			(thermal_bridge_width 0.5)
			(island_removal_mode 0)
		)
		(polygon
			(pts
				(arc
					(start 353.581462 -280.581354)
					(mid 353.384612 -280.778204)
					(end 353.581462 -280.975054)
				)
				(arc
					(start 354.521262 -280.975054)
					(mid 354.718112 -280.778204)
					(end 354.521262 -280.581354)
				)
			)
		)
	)
	(zone
		(layers "F.Cu" "B.Cu" "In1.Cu" "In2.Cu" "In3.Cu" "In4.Cu" "In5.Cu" "In6.Cu"
			"In7.Cu" "In8.Cu" "In9.Cu" "In10.Cu" "In11.Cu" "In12.Cu" "In13.Cu" "In14.Cu"
			"In15.Cu" "In16.Cu"
		)
		(hatch none 0.5)
		(connect_pads
			(clearance 0)
		)
		(min_thickness 0.25)
		(keepout
			(tracks not_allowed)
			(vias allowed)
			(pads allowed)
			(copperpour not_allowed)
			(footprints allowed)
		)
		(placement
			(enabled no)
			(sheetname "")
		)
		(fill
			(thermal_gap 0.5)
			(thermal_bridge_width 0.5)
			(island_removal_mode 0)
		)
		(polygon
			(pts
				(arc
					(start 350.92513 -288.831274)
					(mid 350.857422 -288.759423)
					(end 350.762316 -288.732976)
				)
				(arc
					(start 350.762316 -288.732976)
					(mid 350.632102 -288.786912)
					(end 350.578166 -288.917126)
				)
				(arc
					(start 350.578166 -288.917126)
					(mid 350.583617 -288.961347)
					(end 350.599502 -289.002978)
				)
				(arc
					(start 351.069148 -289.892994)
					(mid 351.136856 -289.964845)
					(end 351.231962 -289.991292)
				)
				(arc
					(start 351.231962 -289.991292)
					(mid 351.362176 -289.937356)
					(end 351.416112 -289.807142)
				)
				(arc
					(start 351.416112 -289.807142)
					(mid 351.410661 -289.762921)
					(end 351.394776 -289.72129)
				)
			)
		)
	)
	(zone
		(layers "F.Cu" "B.Cu" "In1.Cu" "In2.Cu" "In3.Cu" "In4.Cu" "In5.Cu" "In6.Cu"
			"In7.Cu" "In8.Cu" "In9.Cu" "In10.Cu" "In11.Cu" "In12.Cu" "In13.Cu" "In14.Cu"
			"In15.Cu" "In16.Cu"
		)
		(hatch none 0.5)
		(connect_pads
			(clearance 0)
		)
		(min_thickness 0.25)
		(keepout
			(tracks not_allowed)
			(vias allowed)
			(pads allowed)
			(copperpour not_allowed)
			(footprints allowed)
		)
		(placement
			(enabled no)
			(sheetname "")
		)
		(fill
			(thermal_gap 0.5)
			(thermal_bridge_width 0.5)
			(island_removal_mode 0)
		)
		(polygon
			(pts
				(arc
					(start 102.24262 -405.22906)
					(mid 102.62362 -405.61006)
					(end 103.00462 -405.22906)
				)
				(arc
					(start 103.00462 -404.36546)
					(mid 102.62362 -403.98446)
					(end 102.24262 -404.36546)
				)
			)
		)
	)
	(zone
		(layers "F.Cu" "B.Cu" "In1.Cu" "In2.Cu" "In3.Cu" "In4.Cu" "In5.Cu" "In6.Cu"
			"In7.Cu" "In8.Cu" "In9.Cu" "In10.Cu" "In11.Cu" "In12.Cu" "In13.Cu" "In14.Cu"
			"In15.Cu" "In16.Cu"
		)
		(hatch none 0.5)
		(connect_pads
			(clearance 0)
		)
		(min_thickness 0.25)
		(keepout
			(tracks not_allowed)
			(vias allowed)
			(pads allowed)
			(copperpour not_allowed)
			(footprints allowed)
		)
		(placement
			(enabled no)
			(sheetname "")
		)
		(fill
			(thermal_gap 0.5)
			(thermal_bridge_width 0.5)
			(island_removal_mode 0)
		)
		(polygon
			(pts
				(arc
					(start 122.720862 -289.003232)
					(mid 122.736786 -288.961481)
					(end 122.742198 -288.917126)
				)
				(arc
					(start 122.742198 -288.917126)
					(mid 122.688262 -288.786912)
					(end 122.558048 -288.732976)
				)
				(arc
					(start 122.558048 -288.732976)
					(mid 122.463028 -288.759384)
					(end 122.395234 -288.83102)
				)
				(arc
					(start 121.92508 -289.721036)
					(mid 121.909156 -289.762787)
					(end 121.903744 -289.807142)
				)
				(arc
					(start 121.903744 -289.807142)
					(mid 121.95768 -289.937356)
					(end 122.087894 -289.991292)
				)
				(arc
					(start 122.087894 -289.991292)
					(mid 122.182914 -289.964884)
					(end 122.250708 -289.893248)
				)
			)
		)
	)
	(zone
		(layers "F.Cu" "B.Cu" "In1.Cu" "In2.Cu" "In3.Cu" "In4.Cu" "In5.Cu" "In6.Cu"
			"In7.Cu" "In8.Cu" "In9.Cu" "In10.Cu" "In11.Cu" "In12.Cu" "In13.Cu" "In14.Cu"
			"In15.Cu" "In16.Cu"
		)
		(hatch none 0.5)
		(connect_pads
			(clearance 0)
		)
		(min_thickness 0.25)
		(keepout
			(tracks not_allowed)
			(vias allowed)
			(pads allowed)
			(copperpour not_allowed)
			(footprints allowed)
		)
		(placement
			(enabled no)
			(sheetname "")
		)
		(fill
			(thermal_gap 0.5)
			(thermal_bridge_width 0.5)
			(island_removal_mode 0)
		)
		(polygon
			(pts
				(arc
					(start 107.269788 -214.622634)
					(mid 106.611928 -214.622634)
					(end 107.269788 -214.622634)
				)
			)
		)
	)
	(zone
		(layers "F.Cu" "B.Cu" "In1.Cu" "In2.Cu" "In3.Cu" "In4.Cu" "In5.Cu" "In6.Cu"
			"In7.Cu" "In8.Cu" "In9.Cu" "In10.Cu" "In11.Cu" "In12.Cu" "In13.Cu" "In14.Cu"
			"In15.Cu" "In16.Cu"
		)
		(hatch none 0.5)
		(connect_pads
			(clearance 0)
		)
		(min_thickness 0.25)
		(keepout
			(tracks not_allowed)
			(vias allowed)
			(pads allowed)
			(copperpour not_allowed)
			(footprints allowed)
		)
		(placement
			(enabled no)
			(sheetname "")
		)
		(fill
			(thermal_gap 0.5)
			(thermal_bridge_width 0.5)
			(island_removal_mode 0)
		)
		(polygon
			(pts
				(arc
					(start 342.162892 -283.219906)
					(mid 341.505032 -283.219906)
					(end 342.162892 -283.219906)
				)
			)
		)
	)
	(zone
		(layers "F.Cu" "B.Cu" "In1.Cu" "In2.Cu" "In3.Cu" "In4.Cu" "In5.Cu" "In6.Cu"
			"In7.Cu" "In8.Cu" "In9.Cu" "In10.Cu" "In11.Cu" "In12.Cu" "In13.Cu" "In14.Cu"
			"In15.Cu" "In16.Cu"
		)
		(hatch none 0.5)
		(connect_pads
			(clearance 0)
		)
		(min_thickness 0.25)
		(keepout
			(tracks not_allowed)
			(vias allowed)
			(pads allowed)
			(copperpour not_allowed)
			(footprints allowed)
		)
		(placement
			(enabled no)
			(sheetname "")
		)
		(fill
			(thermal_gap 0.5)
			(thermal_bridge_width 0.5)
			(island_removal_mode 0)
		)
		(polygon
			(pts
				(arc
					(start 121.367296 -221.133924)
					(mid 120.709436 -221.133924)
					(end 121.367296 -221.133924)
				)
			)
		)
	)
	(zone
		(layers "F.Cu" "B.Cu" "In1.Cu" "In2.Cu" "In3.Cu" "In4.Cu" "In5.Cu" "In6.Cu"
			"In7.Cu" "In8.Cu" "In9.Cu" "In10.Cu" "In11.Cu" "In12.Cu" "In13.Cu" "In14.Cu"
			"In15.Cu" "In16.Cu"
		)
		(hatch none 0.5)
		(connect_pads
			(clearance 0)
		)
		(min_thickness 0.25)
		(keepout
			(tracks not_allowed)
			(vias allowed)
			(pads allowed)
			(copperpour not_allowed)
			(footprints allowed)
		)
		(placement
			(enabled no)
			(sheetname "")
		)
		(fill
			(thermal_gap 0.5)
			(thermal_bridge_width 0.5)
			(island_removal_mode 0)
		)
		(polygon
			(pts
				(arc
					(start 409.52801 -409.649168)
					(mid 409.14701 -410.030168)
					(end 409.52801 -410.411168)
				)
				(arc
					(start 410.39161 -410.411168)
					(mid 410.77261 -410.030168)
					(end 410.39161 -409.649168)
				)
			)
		)
	)
	(zone
		(layers "F.Cu" "B.Cu" "In1.Cu" "In2.Cu" "In3.Cu" "In4.Cu" "In5.Cu" "In6.Cu"
			"In7.Cu" "In8.Cu" "In9.Cu" "In10.Cu" "In11.Cu" "In12.Cu" "In13.Cu" "In14.Cu"
			"In15.Cu" "In16.Cu"
		)
		(hatch none 0.5)
		(connect_pads
			(clearance 0)
		)
		(min_thickness 0.25)
		(keepout
			(tracks not_allowed)
			(vias allowed)
			(pads allowed)
			(copperpour not_allowed)
			(footprints allowed)
		)
		(placement
			(enabled no)
			(sheetname "")
		)
		(fill
			(thermal_gap 0.5)
			(thermal_bridge_width 0.5)
			(island_removal_mode 0)
		)
		(polygon
			(pts
				(arc
					(start 16.283178 -5.169154)
					(mid 14.352778 -5.169154)
					(end 16.283178 -5.169154)
				)
			)
		)
	)
	(zone
		(layers "F.Cu" "B.Cu" "In1.Cu" "In2.Cu" "In3.Cu" "In4.Cu" "In5.Cu" "In6.Cu"
			"In7.Cu" "In8.Cu" "In9.Cu" "In10.Cu" "In11.Cu" "In12.Cu" "In13.Cu" "In14.Cu"
			"In15.Cu" "In16.Cu"
		)
		(hatch none 0.5)
		(connect_pads
			(clearance 0)
		)
		(min_thickness 0.25)
		(keepout
			(tracks not_allowed)
			(vias allowed)
			(pads allowed)
			(copperpour not_allowed)
			(footprints allowed)
		)
		(placement
			(enabled no)
			(sheetname "")
		)
		(fill
			(thermal_gap 0.5)
			(thermal_bridge_width 0.5)
			(island_removal_mode 0)
		)
		(polygon
			(pts
				(arc
					(start 329.832208 -406.62352)
					(mid 329.451208 -407.00452)
					(end 329.832208 -407.38552)
				)
				(arc
					(start 330.695808 -407.38552)
					(mid 331.076808 -407.00452)
					(end 330.695808 -406.62352)
				)
			)
		)
	)
	(zone
		(layers "F.Cu" "B.Cu" "In1.Cu" "In2.Cu" "In3.Cu" "In4.Cu" "In5.Cu" "In6.Cu"
			"In7.Cu" "In8.Cu" "In9.Cu" "In10.Cu" "In11.Cu" "In12.Cu" "In13.Cu" "In14.Cu"
			"In15.Cu" "In16.Cu"
		)
		(hatch none 0.5)
		(connect_pads
			(clearance 0)
		)
		(min_thickness 0.25)
		(keepout
			(tracks not_allowed)
			(vias allowed)
			(pads allowed)
			(copperpour not_allowed)
			(footprints allowed)
		)
		(placement
			(enabled no)
			(sheetname "")
		)
		(fill
			(thermal_gap 0.5)
			(thermal_bridge_width 0.5)
			(island_removal_mode 0)
		)
		(polygon
			(pts
				(arc
					(start 103.59136 -285.563056)
					(mid 103.571676 -285.610466)
					(end 103.564944 -285.661354)
				)
				(arc
					(start 103.564944 -285.661354)
					(mid 103.6226 -285.800548)
					(end 103.761794 -285.858204)
				)
				(arc
					(start 103.761794 -285.858204)
					(mid 103.860225 -285.831788)
					(end 103.932228 -285.759652)
				)
				(arc
					(start 104.402128 -284.945582)
					(mid 104.421812 -284.898172)
					(end 104.428544 -284.847284)
				)
				(arc
					(start 104.428544 -284.847284)
					(mid 104.370888 -284.70809)
					(end 104.231694 -284.650434)
				)
				(arc
					(start 104.231694 -284.650434)
					(mid 104.133263 -284.67685)
					(end 104.06126 -284.748986)
				)
			)
		)
	)
	(zone
		(layers "F.Cu" "B.Cu" "In1.Cu" "In2.Cu" "In3.Cu" "In4.Cu" "In5.Cu" "In6.Cu"
			"In7.Cu" "In8.Cu" "In9.Cu" "In10.Cu" "In11.Cu" "In12.Cu" "In13.Cu" "In14.Cu"
			"In15.Cu" "In16.Cu"
		)
		(hatch none 0.5)
		(connect_pads
			(clearance 0)
		)
		(min_thickness 0.25)
		(keepout
			(tracks not_allowed)
			(vias allowed)
			(pads allowed)
			(copperpour not_allowed)
			(footprints allowed)
		)
		(placement
			(enabled no)
			(sheetname "")
		)
		(fill
			(thermal_gap 0.5)
			(thermal_bridge_width 0.5)
			(island_removal_mode 0)
		)
		(polygon
			(pts
				(arc
					(start 89.335864 -285.661354)
					(mid 89.993724 -285.661354)
					(end 89.335864 -285.661354)
				)
			)
		)
	)
	(zone
		(layers "F.Cu" "B.Cu" "In1.Cu" "In2.Cu" "In3.Cu" "In4.Cu" "In5.Cu" "In6.Cu"
			"In7.Cu" "In8.Cu" "In9.Cu" "In10.Cu" "In11.Cu" "In12.Cu" "In13.Cu" "In14.Cu"
			"In15.Cu" "In16.Cu"
		)
		(hatch none 0.5)
		(connect_pads
			(clearance 0)
		)
		(min_thickness 0.25)
		(keepout
			(tracks not_allowed)
			(vias allowed)
			(pads allowed)
			(copperpour not_allowed)
			(footprints allowed)
		)
		(placement
			(enabled no)
			(sheetname "")
		)
		(fill
			(thermal_gap 0.5)
			(thermal_bridge_width 0.5)
			(island_removal_mode 0)
		)
		(polygon
			(pts
				(arc
					(start 398.423384 -18.744438)
					(mid 398.042384 -19.125438)
					(end 398.423384 -19.506438)
				)
				(arc
					(start 399.286984 -19.506438)
					(mid 399.667984 -19.125438)
					(end 399.286984 -18.744438)
				)
			)
		)
	)
	(zone
		(layers "F.Cu" "B.Cu" "In1.Cu" "In2.Cu" "In3.Cu" "In4.Cu" "In5.Cu" "In6.Cu"
			"In7.Cu" "In8.Cu" "In9.Cu" "In10.Cu" "In11.Cu" "In12.Cu" "In13.Cu" "In14.Cu"
			"In15.Cu" "In16.Cu"
		)
		(hatch none 0.5)
		(connect_pads
			(clearance 0)
		)
		(min_thickness 0.25)
		(keepout
			(tracks not_allowed)
			(vias allowed)
			(pads allowed)
			(copperpour not_allowed)
			(footprints allowed)
		)
		(placement
			(enabled no)
			(sheetname "")
		)
		(fill
			(thermal_gap 0.5)
			(thermal_bridge_width 0.5)
			(island_removal_mode 0)
		)
		(polygon
			(pts
				(arc
					(start 357.199692 -276.708616)
					(mid 356.541832 -276.708616)
					(end 357.199692 -276.708616)
				)
			)
		)
	)
	(zone
		(layers "F.Cu" "B.Cu" "In1.Cu" "In2.Cu" "In3.Cu" "In4.Cu" "In5.Cu" "In6.Cu"
			"In7.Cu" "In8.Cu" "In9.Cu" "In10.Cu" "In11.Cu" "In12.Cu" "In13.Cu" "In14.Cu"
			"In15.Cu" "In16.Cu"
		)
		(hatch none 0.5)
		(connect_pads
			(clearance 0)
		)
		(min_thickness 0.25)
		(keepout
			(tracks not_allowed)
			(vias allowed)
			(pads allowed)
			(copperpour not_allowed)
			(footprints allowed)
		)
		(placement
			(enabled no)
			(sheetname "")
		)
		(fill
			(thermal_gap 0.5)
			(thermal_bridge_width 0.5)
			(island_removal_mode 0)
		)
		(polygon
			(pts
				(arc
					(start 124.027692 -221.231968)
					(mid 124.047376 -221.184558)
					(end 124.054108 -221.13367)
				)
				(arc
					(start 124.054108 -221.13367)
					(mid 123.996452 -220.994476)
					(end 123.857258 -220.93682)
				)
				(arc
					(start 123.857258 -220.93682)
					(mid 123.758827 -220.963236)
					(end 123.686824 -221.035372)
				)
				(arc
					(start 123.217178 -221.849442)
					(mid 123.197494 -221.896852)
					(end 123.190762 -221.94774)
				)
				(arc
					(start 123.190762 -221.94774)
					(mid 123.248418 -222.086934)
					(end 123.387612 -222.14459)
				)
				(arc
					(start 123.387612 -222.14459)
					(mid 123.486043 -222.118174)
					(end 123.558046 -222.046038)
				)
			)
		)
	)
	(zone
		(layers "F.Cu" "B.Cu" "In1.Cu" "In2.Cu" "In3.Cu" "In4.Cu" "In5.Cu" "In6.Cu"
			"In7.Cu" "In8.Cu" "In9.Cu" "In10.Cu" "In11.Cu" "In12.Cu" "In13.Cu" "In14.Cu"
			"In15.Cu" "In16.Cu"
		)
		(hatch none 0.5)
		(connect_pads
			(clearance 0)
		)
		(min_thickness 0.25)
		(keepout
			(tracks not_allowed)
			(vias allowed)
			(pads allowed)
			(copperpour not_allowed)
			(footprints allowed)
		)
		(placement
			(enabled no)
			(sheetname "")
		)
		(fill
			(thermal_gap 0.5)
			(thermal_bridge_width 0.5)
			(island_removal_mode 0)
		)
		(polygon
			(pts
				(arc
					(start 95.466662 -288.831274)
					(mid 95.398954 -288.759423)
					(end 95.303848 -288.732976)
				)
				(arc
					(start 95.303848 -288.732976)
					(mid 95.173634 -288.786912)
					(end 95.119698 -288.917126)
				)
				(arc
					(start 95.119698 -288.917126)
					(mid 95.125149 -288.961347)
					(end 95.141034 -289.002978)
				)
				(arc
					(start 95.61068 -289.892994)
					(mid 95.678388 -289.964845)
					(end 95.773494 -289.991292)
				)
				(arc
					(start 95.773494 -289.991292)
					(mid 95.903708 -289.937356)
					(end 95.957644 -289.807142)
				)
				(arc
					(start 95.957644 -289.807142)
					(mid 95.952193 -289.762921)
					(end 95.936308 -289.72129)
				)
			)
		)
	)
	(zone
		(layers "F.Cu" "B.Cu" "In1.Cu" "In2.Cu" "In3.Cu" "In4.Cu" "In5.Cu" "In6.Cu"
			"In7.Cu" "In8.Cu" "In9.Cu" "In10.Cu" "In11.Cu" "In12.Cu" "In13.Cu" "In14.Cu"
			"In15.Cu" "In16.Cu"
		)
		(hatch none 0.5)
		(connect_pads
			(clearance 0)
		)
		(min_thickness 0.25)
		(keepout
			(tracks not_allowed)
			(vias allowed)
			(pads allowed)
			(copperpour not_allowed)
			(footprints allowed)
		)
		(placement
			(enabled no)
			(sheetname "")
		)
		(fill
			(thermal_gap 0.5)
			(thermal_bridge_width 0.5)
			(island_removal_mode 0)
		)
		(polygon
			(pts
				(arc
					(start 102.681278 -288.103056)
					(mid 102.023418 -288.103056)
					(end 102.681278 -288.103056)
				)
			)
		)
	)
	(zone
		(layers "F.Cu" "B.Cu" "In1.Cu" "In2.Cu" "In3.Cu" "In4.Cu" "In5.Cu" "In6.Cu"
			"In7.Cu" "In8.Cu" "In9.Cu" "In10.Cu" "In11.Cu" "In12.Cu" "In13.Cu" "In14.Cu"
			"In15.Cu" "In16.Cu"
		)
		(hatch none 0.5)
		(connect_pads
			(clearance 0)
		)
		(min_thickness 0.25)
		(keepout
			(tracks not_allowed)
			(vias allowed)
			(pads allowed)
			(copperpour not_allowed)
			(footprints allowed)
		)
		(placement
			(enabled no)
			(sheetname "")
		)
		(fill
			(thermal_gap 0.5)
			(thermal_bridge_width 0.5)
			(island_removal_mode 0)
		)
		(polygon
			(pts
				(arc
					(start 58.142124 -420.760398)
					(mid 58.164442 -420.81428)
					(end 58.218324 -420.836598)
				)
				(arc
					(start 59.158124 -420.836598)
					(mid 59.212006 -420.81428)
					(end 59.234324 -420.760398)
				)
				(arc
					(start 59.234324 -418.218874)
					(mid 59.212006 -418.164992)
					(end 59.158124 -418.142674)
				)
				(arc
					(start 58.218324 -418.142674)
					(mid 58.164442 -418.164992)
					(end 58.142124 -418.218874)
				)
			)
		)
	)
	(zone
		(layers "F.Cu" "B.Cu" "In1.Cu" "In2.Cu" "In3.Cu" "In4.Cu" "In5.Cu" "In6.Cu"
			"In7.Cu" "In8.Cu" "In9.Cu" "In10.Cu" "In11.Cu" "In12.Cu" "In13.Cu" "In14.Cu"
			"In15.Cu" "In16.Cu"
		)
		(hatch none 0.5)
		(connect_pads
			(clearance 0)
		)
		(min_thickness 0.25)
		(keepout
			(tracks not_allowed)
			(vias allowed)
			(pads allowed)
			(copperpour not_allowed)
			(footprints allowed)
		)
		(placement
			(enabled no)
			(sheetname "")
		)
		(fill
			(thermal_gap 0.5)
			(thermal_bridge_width 0.5)
			(island_removal_mode 0)
		)
		(polygon
			(pts
				(arc
					(start 128.807464 -285.661354)
					(mid 129.465324 -285.661354)
					(end 128.807464 -285.661354)
				)
			)
		)
	)
	(zone
		(layers "F.Cu" "B.Cu" "In1.Cu" "In2.Cu" "In3.Cu" "In4.Cu" "In5.Cu" "In6.Cu"
			"In7.Cu" "In8.Cu" "In9.Cu" "In10.Cu" "In11.Cu" "In12.Cu" "In13.Cu" "In14.Cu"
			"In15.Cu" "In16.Cu"
		)
		(hatch none 0.5)
		(connect_pads
			(clearance 0)
		)
		(min_thickness 0.25)
		(keepout
			(tracks not_allowed)
			(vias allowed)
			(pads allowed)
			(copperpour not_allowed)
			(footprints allowed)
		)
		(placement
			(enabled no)
			(sheetname "")
		)
		(fill
			(thermal_gap 0.5)
			(thermal_bridge_width 0.5)
			(island_removal_mode 0)
		)
		(polygon
			(pts
				(arc
					(start 163.040314 -400.477228)
					(mid 162.659314 -400.858228)
					(end 163.040314 -401.239228)
				)
				(arc
					(start 163.903914 -401.239228)
					(mid 164.284914 -400.858228)
					(end 163.903914 -400.477228)
				)
			)
		)
	)
	(zone
		(layers "F.Cu" "B.Cu" "In1.Cu" "In2.Cu" "In3.Cu" "In4.Cu" "In5.Cu" "In6.Cu"
			"In7.Cu" "In8.Cu" "In9.Cu" "In10.Cu" "In11.Cu" "In12.Cu" "In13.Cu" "In14.Cu"
			"In15.Cu" "In16.Cu"
		)
		(hatch none 0.5)
		(connect_pads
			(clearance 0)
		)
		(min_thickness 0.25)
		(keepout
			(tracks not_allowed)
			(vias allowed)
			(pads allowed)
			(copperpour not_allowed)
			(footprints allowed)
		)
		(placement
			(enabled no)
			(sheetname "")
		)
		(fill
			(thermal_gap 0.5)
			(thermal_bridge_width 0.5)
			(island_removal_mode 0)
		)
		(polygon
			(pts
				(arc
					(start 134.005828 -285.759652)
					(mid 134.025512 -285.712242)
					(end 134.032244 -285.661354)
				)
				(arc
					(start 134.032244 -285.661354)
					(mid 133.974588 -285.52216)
					(end 133.835394 -285.464504)
				)
				(arc
					(start 133.835394 -285.464504)
					(mid 133.736963 -285.49092)
					(end 133.66496 -285.563056)
				)
				(arc
					(start 133.195314 -286.377126)
					(mid 133.17563 -286.424536)
					(end 133.168898 -286.475424)
				)
				(arc
					(start 133.168898 -286.475424)
					(mid 133.226554 -286.614618)
					(end 133.365748 -286.672274)
				)
				(arc
					(start 133.365748 -286.672274)
					(mid 133.464179 -286.645858)
					(end 133.536182 -286.573722)
				)
			)
		)
	)
	(zone
		(layers "F.Cu" "B.Cu" "In1.Cu" "In2.Cu" "In3.Cu" "In4.Cu" "In5.Cu" "In6.Cu"
			"In7.Cu" "In8.Cu" "In9.Cu" "In10.Cu" "In11.Cu" "In12.Cu" "In13.Cu" "In14.Cu"
			"In15.Cu" "In16.Cu"
		)
		(hatch none 0.5)
		(connect_pads
			(clearance 0)
		)
		(min_thickness 0.25)
		(keepout
			(tracks not_allowed)
			(vias allowed)
			(pads allowed)
			(copperpour not_allowed)
			(footprints allowed)
		)
		(placement
			(enabled no)
			(sheetname "")
		)
		(fill
			(thermal_gap 0.5)
			(thermal_bridge_width 0.5)
			(island_removal_mode 0)
		)
		(polygon
			(pts
				(arc
					(start 350.762062 -278.953468)
					(mid 350.565212 -279.150318)
					(end 350.762062 -279.347168)
				)
				(arc
					(start 351.701862 -279.347168)
					(mid 351.898712 -279.150318)
					(end 351.701862 -278.953468)
				)
			)
		)
	)
	(zone
		(layers "F.Cu" "B.Cu" "In1.Cu" "In2.Cu" "In3.Cu" "In4.Cu" "In5.Cu" "In6.Cu"
			"In7.Cu" "In8.Cu" "In9.Cu" "In10.Cu" "In11.Cu" "In12.Cu" "In13.Cu" "In14.Cu"
			"In15.Cu" "In16.Cu"
		)
		(hatch none 0.5)
		(connect_pads
			(clearance 0)
		)
		(min_thickness 0.25)
		(keepout
			(tracks not_allowed)
			(vias allowed)
			(pads allowed)
			(copperpour not_allowed)
			(footprints allowed)
		)
		(placement
			(enabled no)
			(sheetname "")
		)
		(fill
			(thermal_gap 0.5)
			(thermal_bridge_width 0.5)
			(island_removal_mode 0)
		)
		(polygon
			(pts
				(arc
					(start 328.08291 -251.76988)
					(mid 323.636894 -251.76988)
					(end 328.08291 -251.76988)
				)
			)
		)
	)
	(zone
		(layers "F.Cu" "B.Cu" "In1.Cu" "In2.Cu" "In3.Cu" "In4.Cu" "In5.Cu" "In6.Cu"
			"In7.Cu" "In8.Cu" "In9.Cu" "In10.Cu" "In11.Cu" "In12.Cu" "In13.Cu" "In14.Cu"
			"In15.Cu" "In16.Cu"
		)
		(hatch none 0.5)
		(connect_pads
			(clearance 0)
		)
		(min_thickness 0.25)
		(keepout
			(tracks not_allowed)
			(vias allowed)
			(pads allowed)
			(copperpour not_allowed)
			(footprints allowed)
		)
		(placement
			(enabled no)
			(sheetname "")
		)
		(fill
			(thermal_gap 0.5)
			(thermal_bridge_width 0.5)
			(island_removal_mode 0)
		)
		(polygon
			(pts
				(arc
					(start 99.673664 -285.661354)
					(mid 100.331524 -285.661354)
					(end 99.673664 -285.661354)
				)
			)
		)
	)
	(zone
		(layers "F.Cu" "B.Cu" "In1.Cu" "In2.Cu" "In3.Cu" "In4.Cu" "In5.Cu" "In6.Cu"
			"In7.Cu" "In8.Cu" "In9.Cu" "In10.Cu" "In11.Cu" "In12.Cu" "In13.Cu" "In14.Cu"
			"In15.Cu" "In16.Cu"
		)
		(hatch none 0.5)
		(connect_pads
			(clearance 0)
		)
		(min_thickness 0.25)
		(keepout
			(tracks not_allowed)
			(vias allowed)
			(pads allowed)
			(copperpour not_allowed)
			(footprints allowed)
		)
		(placement
			(enabled no)
			(sheetname "")
		)
		(fill
			(thermal_gap 0.5)
			(thermal_bridge_width 0.5)
			(island_removal_mode 0)
		)
		(polygon
			(pts
				(arc
					(start 101.942646 -223.67367)
					(mid 101.96233 -223.62626)
					(end 101.969062 -223.575372)
				)
				(arc
					(start 101.969062 -223.575372)
					(mid 101.911406 -223.436178)
					(end 101.772212 -223.378522)
				)
				(arc
					(start 101.772212 -223.378522)
					(mid 101.673781 -223.404938)
					(end 101.601778 -223.477074)
				)
				(arc
					(start 101.132132 -224.291144)
					(mid 101.112448 -224.338554)
					(end 101.105716 -224.389442)
				)
				(arc
					(start 101.105716 -224.389442)
					(mid 101.163372 -224.528636)
					(end 101.302566 -224.586292)
				)
				(arc
					(start 101.302566 -224.586292)
					(mid 101.400997 -224.559876)
					(end 101.473 -224.48774)
				)
			)
		)
	)
	(zone
		(layers "F.Cu" "B.Cu" "In1.Cu" "In2.Cu" "In3.Cu" "In4.Cu" "In5.Cu" "In6.Cu"
			"In7.Cu" "In8.Cu" "In9.Cu" "In10.Cu" "In11.Cu" "In12.Cu" "In13.Cu" "In14.Cu"
			"In15.Cu" "In16.Cu"
		)
		(hatch none 0.5)
		(connect_pads
			(clearance 0)
		)
		(min_thickness 0.25)
		(keepout
			(tracks not_allowed)
			(vias allowed)
			(pads allowed)
			(copperpour not_allowed)
			(footprints allowed)
		)
		(placement
			(enabled no)
			(sheetname "")
		)
		(fill
			(thermal_gap 0.5)
			(thermal_bridge_width 0.5)
			(island_removal_mode 0)
		)
		(polygon
			(pts
				(arc
					(start 378.815346 -284.847538)
					(mid 378.157486 -284.847538)
					(end 378.815346 -284.847538)
				)
			)
		)
	)
	(zone
		(layers "F.Cu" "B.Cu" "In1.Cu" "In2.Cu" "In3.Cu" "In4.Cu" "In5.Cu" "In6.Cu"
			"In7.Cu" "In8.Cu" "In9.Cu" "In10.Cu" "In11.Cu" "In12.Cu" "In13.Cu" "In14.Cu"
			"In15.Cu" "In16.Cu"
		)
		(hatch none 0.5)
		(connect_pads
			(clearance 0)
		)
		(min_thickness 0.25)
		(keepout
			(tracks not_allowed)
			(vias allowed)
			(pads allowed)
			(copperpour not_allowed)
			(footprints allowed)
		)
		(placement
			(enabled no)
			(sheetname "")
		)
		(fill
			(thermal_gap 0.5)
			(thermal_bridge_width 0.5)
			(island_removal_mode 0)
		)
		(polygon
			(pts
				(arc
					(start 350.621346 -279.964134)
					(mid 349.963486 -279.964134)
					(end 350.621346 -279.964134)
				)
			)
		)
	)
	(zone
		(layers "F.Cu" "B.Cu" "In1.Cu" "In2.Cu" "In3.Cu" "In4.Cu" "In5.Cu" "In6.Cu"
			"In7.Cu" "In8.Cu" "In9.Cu" "In10.Cu" "In11.Cu" "In12.Cu" "In13.Cu" "In14.Cu"
			"In15.Cu" "In16.Cu"
		)
		(hatch none 0.5)
		(connect_pads
			(clearance 0)
		)
		(min_thickness 0.25)
		(keepout
			(tracks not_allowed)
			(vias allowed)
			(pads allowed)
			(copperpour not_allowed)
			(footprints allowed)
		)
		(placement
			(enabled no)
			(sheetname "")
		)
		(fill
			(thermal_gap 0.5)
			(thermal_bridge_width 0.5)
			(island_removal_mode 0)
		)
		(polygon
			(pts
				(arc
					(start 95.522542 -221.94774)
					(mid 94.864682 -221.94774)
					(end 95.522542 -221.94774)
				)
			)
		)
	)
	(zone
		(layers "F.Cu" "B.Cu" "In1.Cu" "In2.Cu" "In3.Cu" "In4.Cu" "In5.Cu" "In6.Cu"
			"In7.Cu" "In8.Cu" "In9.Cu" "In10.Cu" "In11.Cu" "In12.Cu" "In13.Cu" "In14.Cu"
			"In15.Cu" "In16.Cu"
		)
		(hatch none 0.5)
		(connect_pads
			(clearance 0)
		)
		(min_thickness 0.25)
		(keepout
			(tracks not_allowed)
			(vias allowed)
			(pads allowed)
			(copperpour not_allowed)
			(footprints allowed)
		)
		(placement
			(enabled no)
			(sheetname "")
		)
		(fill
			(thermal_gap 0.5)
			(thermal_bridge_width 0.5)
			(island_removal_mode 0)
		)
		(polygon
			(pts
				(arc
					(start 350.621346 -288.103056)
					(mid 349.963486 -288.103056)
					(end 350.621346 -288.103056)
				)
			)
		)
	)
	(zone
		(layers "F.Cu" "B.Cu" "In1.Cu" "In2.Cu" "In3.Cu" "In4.Cu" "In5.Cu" "In6.Cu"
			"In7.Cu" "In8.Cu" "In9.Cu" "In10.Cu" "In11.Cu" "In12.Cu" "In13.Cu" "In14.Cu"
			"In15.Cu" "In16.Cu"
		)
		(hatch none 0.5)
		(connect_pads
			(clearance 0)
		)
		(min_thickness 0.25)
		(keepout
			(tracks not_allowed)
			(vias allowed)
			(pads allowed)
			(copperpour not_allowed)
			(footprints allowed)
		)
		(placement
			(enabled no)
			(sheetname "")
		)
		(fill
			(thermal_gap 0.5)
			(thermal_bridge_width 0.5)
			(island_removal_mode 0)
		)
		(polygon
			(pts
				(arc
					(start 248.767346 2.4892)
					(mid 249.148346 2.1082)
					(end 249.529346 2.4892)
				)
				(arc
					(start 249.529346 3.3528)
					(mid 249.148346 3.7338)
					(end 248.767346 3.3528)
				)
			)
		)
	)
	(zone
		(layers "F.Cu" "B.Cu" "In1.Cu" "In2.Cu" "In3.Cu" "In4.Cu" "In5.Cu" "In6.Cu"
			"In7.Cu" "In8.Cu" "In9.Cu" "In10.Cu" "In11.Cu" "In12.Cu" "In13.Cu" "In14.Cu"
			"In15.Cu" "In16.Cu"
		)
		(hatch none 0.5)
		(connect_pads
			(clearance 0)
		)
		(min_thickness 0.25)
		(keepout
			(tracks not_allowed)
			(vias allowed)
			(pads allowed)
			(copperpour not_allowed)
			(footprints allowed)
		)
		(placement
			(enabled no)
			(sheetname "")
		)
		(fill
			(thermal_gap 0.5)
			(thermal_bridge_width 0.5)
			(island_removal_mode 0)
		)
		(polygon
			(pts
				(arc
					(start 125.077982 -284.74924)
					(mid 125.005993 -284.677081)
					(end 124.907548 -284.650688)
				)
				(arc
					(start 124.907548 -284.650688)
					(mid 124.768354 -284.708344)
					(end 124.710698 -284.847538)
				)
				(arc
					(start 124.710698 -284.847538)
					(mid 124.717455 -284.898419)
					(end 124.737114 -284.945836)
				)
				(arc
					(start 125.20676 -285.759652)
					(mid 125.278749 -285.831811)
					(end 125.377194 -285.858204)
				)
				(arc
					(start 125.377194 -285.858204)
					(mid 125.516388 -285.800548)
					(end 125.574044 -285.661354)
				)
				(arc
					(start 125.574044 -285.661354)
					(mid 125.567287 -285.610473)
					(end 125.547628 -285.563056)
				)
			)
		)
	)
	(zone
		(layers "F.Cu" "B.Cu" "In1.Cu" "In2.Cu" "In3.Cu" "In4.Cu" "In5.Cu" "In6.Cu"
			"In7.Cu" "In8.Cu" "In9.Cu" "In10.Cu" "In11.Cu" "In12.Cu" "In13.Cu" "In14.Cu"
			"In15.Cu" "In16.Cu"
		)
		(hatch none 0.5)
		(connect_pads
			(clearance 0)
		)
		(min_thickness 0.25)
		(keepout
			(tracks not_allowed)
			(vias allowed)
			(pads allowed)
			(copperpour not_allowed)
			(footprints allowed)
		)
		(placement
			(enabled no)
			(sheetname "")
		)
		(fill
			(thermal_gap 0.5)
			(thermal_bridge_width 0.5)
			(island_removal_mode 0)
		)
		(polygon
			(pts
				(arc
					(start 125.596142 -221.94774)
					(mid 124.938282 -221.94774)
					(end 125.596142 -221.94774)
				)
			)
		)
	)
	(zone
		(layers "F.Cu" "B.Cu" "In1.Cu" "In2.Cu" "In3.Cu" "In4.Cu" "In5.Cu" "In6.Cu"
			"In7.Cu" "In8.Cu" "In9.Cu" "In10.Cu" "In11.Cu" "In12.Cu" "In13.Cu" "In14.Cu"
			"In15.Cu" "In16.Cu"
		)
		(hatch none 0.5)
		(connect_pads
			(clearance 0)
		)
		(min_thickness 0.25)
		(keepout
			(tracks not_allowed)
			(vias allowed)
			(pads allowed)
			(copperpour not_allowed)
			(footprints allowed)
		)
		(placement
			(enabled no)
			(sheetname "")
		)
		(fill
			(thermal_gap 0.5)
			(thermal_bridge_width 0.5)
			(island_removal_mode 0)
		)
		(polygon
			(pts
				(arc
					(start 108.210096 -217.878406)
					(mid 107.552236 -217.878406)
					(end 108.210096 -217.878406)
				)
			)
		)
	)
	(zone
		(layers "F.Cu" "B.Cu" "In1.Cu" "In2.Cu" "In3.Cu" "In4.Cu" "In5.Cu" "In6.Cu"
			"In7.Cu" "In8.Cu" "In9.Cu" "In10.Cu" "In11.Cu" "In12.Cu" "In13.Cu" "In14.Cu"
			"In15.Cu" "In16.Cu"
		)
		(hatch none 0.5)
		(connect_pads
			(clearance 0)
		)
		(min_thickness 0.25)
		(keepout
			(tracks not_allowed)
			(vias allowed)
			(pads allowed)
			(copperpour not_allowed)
			(footprints allowed)
		)
		(placement
			(enabled no)
			(sheetname "")
		)
		(fill
			(thermal_gap 0.5)
			(thermal_bridge_width 0.5)
			(island_removal_mode 0)
		)
		(polygon
			(pts
				(arc
					(start 466.808058 -32.29991)
					(mid 464.75015 -30.242002)
					(end 462.691988 -32.29991)
				)
				(arc
					(start 462.691988 -33.90011)
					(mid 464.75015 -35.958272)
					(end 466.808058 -33.90011)
				)
			)
		)
	)
	(zone
		(layers "F.Cu" "B.Cu" "In1.Cu" "In2.Cu" "In3.Cu" "In4.Cu" "In5.Cu" "In6.Cu"
			"In7.Cu" "In8.Cu" "In9.Cu" "In10.Cu" "In11.Cu" "In12.Cu" "In13.Cu" "In14.Cu"
			"In15.Cu" "In16.Cu"
		)
		(hatch none 0.5)
		(connect_pads
			(clearance 0)
		)
		(min_thickness 0.25)
		(keepout
			(tracks not_allowed)
			(vias allowed)
			(pads allowed)
			(copperpour not_allowed)
			(footprints allowed)
		)
		(placement
			(enabled no)
			(sheetname "")
		)
		(fill
			(thermal_gap 0.5)
			(thermal_bridge_width 0.5)
			(island_removal_mode 0)
		)
		(polygon
			(pts
				(arc
					(start 130.12928 -213.646766)
					(mid 130.061572 -213.574915)
					(end 129.966466 -213.548468)
				)
				(arc
					(start 129.966466 -213.548468)
					(mid 129.836252 -213.602404)
					(end 129.782316 -213.732618)
				)
				(arc
					(start 129.782316 -213.732618)
					(mid 129.787767 -213.776839)
					(end 129.803652 -213.81847)
				)
				(arc
					(start 130.273044 -214.708486)
					(mid 130.340752 -214.780337)
					(end 130.435858 -214.806784)
				)
				(arc
					(start 130.435858 -214.806784)
					(mid 130.566072 -214.752848)
					(end 130.620008 -214.622634)
				)
				(arc
					(start 130.620008 -214.622634)
					(mid 130.614557 -214.578413)
					(end 130.598672 -214.536782)
				)
			)
		)
	)
	(zone
		(layers "F.Cu" "B.Cu" "In1.Cu" "In2.Cu" "In3.Cu" "In4.Cu" "In5.Cu" "In6.Cu"
			"In7.Cu" "In8.Cu" "In9.Cu" "In10.Cu" "In11.Cu" "In12.Cu" "In13.Cu" "In14.Cu"
			"In15.Cu" "In16.Cu"
		)
		(hatch none 0.5)
		(connect_pads
			(clearance 0)
		)
		(min_thickness 0.25)
		(keepout
			(tracks not_allowed)
			(vias allowed)
			(pads allowed)
			(copperpour not_allowed)
			(footprints allowed)
		)
		(placement
			(enabled no)
			(sheetname "")
		)
		(fill
			(thermal_gap 0.5)
			(thermal_bridge_width 0.5)
			(island_removal_mode 0)
		)
		(polygon
			(pts
				(arc
					(start 336.994246 -288.917126)
					(mid 336.336386 -288.917126)
					(end 336.994246 -288.917126)
				)
			)
		)
	)
	(zone
		(layers "F.Cu" "B.Cu" "In1.Cu" "In2.Cu" "In3.Cu" "In4.Cu" "In5.Cu" "In6.Cu"
			"In7.Cu" "In8.Cu" "In9.Cu" "In10.Cu" "In11.Cu" "In12.Cu" "In13.Cu" "In14.Cu"
			"In15.Cu" "In16.Cu"
		)
		(hatch none 0.5)
		(connect_pads
			(clearance 0)
		)
		(min_thickness 0.25)
		(keepout
			(tracks not_allowed)
			(vias allowed)
			(pads allowed)
			(copperpour not_allowed)
			(footprints allowed)
		)
		(placement
			(enabled no)
			(sheetname "")
		)
		(fill
			(thermal_gap 0.5)
			(thermal_bridge_width 0.5)
			(island_removal_mode 0)
		)
		(polygon
			(pts
				(arc
					(start 159.94253 -43.818556)
					(mid 159.56153 -43.437556)
					(end 159.18053 -43.818556)
				)
				(arc
					(start 159.18053 -44.682156)
					(mid 159.56153 -45.063156)
					(end 159.94253 -44.682156)
				)
			)
		)
	)
	(zone
		(layers "F.Cu" "B.Cu" "In1.Cu" "In2.Cu" "In3.Cu" "In4.Cu" "In5.Cu" "In6.Cu"
			"In7.Cu" "In8.Cu" "In9.Cu" "In10.Cu" "In11.Cu" "In12.Cu" "In13.Cu" "In14.Cu"
			"In15.Cu" "In16.Cu"
		)
		(hatch none 0.5)
		(connect_pads
			(clearance 0)
		)
		(min_thickness 0.25)
		(keepout
			(tracks not_allowed)
			(vias allowed)
			(pads allowed)
			(copperpour not_allowed)
			(footprints allowed)
		)
		(placement
			(enabled no)
			(sheetname "")
		)
		(fill
			(thermal_gap 0.5)
			(thermal_bridge_width 0.5)
			(island_removal_mode 0)
		)
		(polygon
			(pts
				(arc
					(start 353.440746 -279.964134)
					(mid 352.782886 -279.964134)
					(end 353.440746 -279.964134)
				)
			)
		)
	)
	(zone
		(layers "F.Cu" "B.Cu" "In1.Cu" "In2.Cu" "In3.Cu" "In4.Cu" "In5.Cu" "In6.Cu"
			"In7.Cu" "In8.Cu" "In9.Cu" "In10.Cu" "In11.Cu" "In12.Cu" "In13.Cu" "In14.Cu"
			"In15.Cu" "In16.Cu"
		)
		(hatch none 0.5)
		(connect_pads
			(clearance 0)
		)
		(min_thickness 0.25)
		(keepout
			(tracks not_allowed)
			(vias allowed)
			(pads allowed)
			(copperpour not_allowed)
			(footprints allowed)
		)
		(placement
			(enabled no)
			(sheetname "")
		)
		(fill
			(thermal_gap 0.5)
			(thermal_bridge_width 0.5)
			(island_removal_mode 0)
		)
		(polygon
			(pts
				(arc
					(start 347.16593 -288.831274)
					(mid 347.098222 -288.759423)
					(end 347.003116 -288.732976)
				)
				(arc
					(start 347.003116 -288.732976)
					(mid 346.872902 -288.786912)
					(end 346.818966 -288.917126)
				)
				(arc
					(start 346.818966 -288.917126)
					(mid 346.824417 -288.961347)
					(end 346.840302 -289.002978)
				)
				(arc
					(start 347.309948 -289.892994)
					(mid 347.377656 -289.964845)
					(end 347.472762 -289.991292)
				)
				(arc
					(start 347.472762 -289.991292)
					(mid 347.602976 -289.937356)
					(end 347.656912 -289.807142)
				)
				(arc
					(start 347.656912 -289.807142)
					(mid 347.651461 -289.762921)
					(end 347.635576 -289.72129)
				)
			)
		)
	)
	(zone
		(layers "F.Cu" "B.Cu" "In1.Cu" "In2.Cu" "In3.Cu" "In4.Cu" "In5.Cu" "In6.Cu"
			"In7.Cu" "In8.Cu" "In9.Cu" "In10.Cu" "In11.Cu" "In12.Cu" "In13.Cu" "In14.Cu"
			"In15.Cu" "In16.Cu"
		)
		(hatch none 0.5)
		(connect_pads
			(clearance 0)
		)
		(min_thickness 0.25)
		(keepout
			(tracks not_allowed)
			(vias allowed)
			(pads allowed)
			(copperpour not_allowed)
			(footprints allowed)
		)
		(placement
			(enabled no)
			(sheetname "")
		)
		(fill
			(thermal_gap 0.5)
			(thermal_bridge_width 0.5)
			(island_removal_mode 0)
		)
		(polygon
			(pts
				(arc
					(start 92.343478 -286.475424)
					(mid 91.685618 -286.475424)
					(end 92.343478 -286.475424)
				)
			)
		)
	)
	(zone
		(layers "F.Cu" "B.Cu" "In1.Cu" "In2.Cu" "In3.Cu" "In4.Cu" "In5.Cu" "In6.Cu"
			"In7.Cu" "In8.Cu" "In9.Cu" "In10.Cu" "In11.Cu" "In12.Cu" "In13.Cu" "In14.Cu"
			"In15.Cu" "In16.Cu"
		)
		(hatch none 0.5)
		(connect_pads
			(clearance 0)
		)
		(min_thickness 0.25)
		(keepout
			(tracks not_allowed)
			(vias allowed)
			(pads allowed)
			(copperpour not_allowed)
			(footprints allowed)
		)
		(placement
			(enabled no)
			(sheetname "")
		)
		(fill
			(thermal_gap 0.5)
			(thermal_bridge_width 0.5)
			(island_removal_mode 0)
		)
		(polygon
			(pts
				(arc
					(start 338.403692 -286.475424)
					(mid 337.745832 -286.475424)
					(end 338.403692 -286.475424)
				)
			)
		)
	)
	(zone
		(layers "F.Cu" "B.Cu" "In1.Cu" "In2.Cu" "In3.Cu" "In4.Cu" "In5.Cu" "In6.Cu"
			"In7.Cu" "In8.Cu" "In9.Cu" "In10.Cu" "In11.Cu" "In12.Cu" "In13.Cu" "In14.Cu"
			"In15.Cu" "In16.Cu"
		)
		(hatch none 0.5)
		(connect_pads
			(clearance 0)
		)
		(min_thickness 0.25)
		(keepout
			(tracks not_allowed)
			(vias allowed)
			(pads allowed)
			(copperpour not_allowed)
			(footprints allowed)
		)
		(placement
			(enabled no)
			(sheetname "")
		)
		(fill
			(thermal_gap 0.5)
			(thermal_bridge_width 0.5)
			(island_removal_mode 0)
		)
		(polygon
			(pts
				(arc
					(start 346.752164 -221.133924)
					(mid 346.094304 -221.133924)
					(end 346.752164 -221.133924)
				)
			)
		)
	)
	(zone
		(layers "F.Cu" "B.Cu" "In1.Cu" "In2.Cu" "In3.Cu" "In4.Cu" "In5.Cu" "In6.Cu"
			"In7.Cu" "In8.Cu" "In9.Cu" "In10.Cu" "In11.Cu" "In12.Cu" "In13.Cu" "In14.Cu"
			"In15.Cu" "In16.Cu"
		)
		(hatch none 0.5)
		(connect_pads
			(clearance 0)
		)
		(min_thickness 0.25)
		(keepout
			(tracks not_allowed)
			(vias allowed)
			(pads allowed)
			(copperpour not_allowed)
			(footprints allowed)
		)
		(placement
			(enabled no)
			(sheetname "")
		)
		(fill
			(thermal_gap 0.5)
			(thermal_bridge_width 0.5)
			(island_removal_mode 0)
		)
		(polygon
			(pts
				(arc
					(start 95.992188 -214.622634)
					(mid 95.334328 -214.622634)
					(end 95.992188 -214.622634)
				)
			)
		)
	)
	(zone
		(layers "F.Cu" "B.Cu" "In1.Cu" "In2.Cu" "In3.Cu" "In4.Cu" "In5.Cu" "In6.Cu"
			"In7.Cu" "In8.Cu" "In9.Cu" "In10.Cu" "In11.Cu" "In12.Cu" "In13.Cu" "In14.Cu"
			"In15.Cu" "In16.Cu"
		)
		(hatch none 0.5)
		(connect_pads
			(clearance 0)
		)
		(min_thickness 0.25)
		(keepout
			(tracks not_allowed)
			(vias allowed)
			(pads allowed)
			(copperpour not_allowed)
			(footprints allowed)
		)
		(placement
			(enabled no)
			(sheetname "")
		)
		(fill
			(thermal_gap 0.5)
			(thermal_bridge_width 0.5)
			(island_removal_mode 0)
		)
		(polygon
			(pts
				(arc
					(start 95.274638 -409.649168)
					(mid 94.893638 -410.030168)
					(end 95.274638 -410.411168)
				)
				(arc
					(start 96.138238 -410.411168)
					(mid 96.519238 -410.030168)
					(end 96.138238 -409.649168)
				)
			)
		)
	)
	(zone
		(layers "F.Cu" "B.Cu" "In1.Cu" "In2.Cu" "In3.Cu" "In4.Cu" "In5.Cu" "In6.Cu"
			"In7.Cu" "In8.Cu" "In9.Cu" "In10.Cu" "In11.Cu" "In12.Cu" "In13.Cu" "In14.Cu"
			"In15.Cu" "In16.Cu"
		)
		(hatch none 0.5)
		(connect_pads
			(clearance 0)
		)
		(min_thickness 0.25)
		(keepout
			(tracks not_allowed)
			(vias allowed)
			(pads allowed)
			(copperpour not_allowed)
			(footprints allowed)
		)
		(placement
			(enabled no)
			(sheetname "")
		)
		(fill
			(thermal_gap 0.5)
			(thermal_bridge_width 0.5)
			(island_removal_mode 0)
		)
		(polygon
			(pts
				(arc
					(start 432.286918 -417.770056)
					(mid 426.778928 -412.262066)
					(end 421.270938 -417.770056)
				)
				(arc
					(start 421.270938 -424.470068)
					(mid 426.778928 -429.978058)
					(end 432.286918 -424.470068)
				)
			)
		)
	)
	(zone
		(layers "F.Cu" "B.Cu" "In1.Cu" "In2.Cu" "In3.Cu" "In4.Cu" "In5.Cu" "In6.Cu"
			"In7.Cu" "In8.Cu" "In9.Cu" "In10.Cu" "In11.Cu" "In12.Cu" "In13.Cu" "In14.Cu"
			"In15.Cu" "In16.Cu"
		)
		(hatch none 0.5)
		(connect_pads
			(clearance 0)
		)
		(min_thickness 0.25)
		(keepout
			(tracks not_allowed)
			(vias allowed)
			(pads allowed)
			(copperpour not_allowed)
			(footprints allowed)
		)
		(placement
			(enabled no)
			(sheetname "")
		)
		(fill
			(thermal_gap 0.5)
			(thermal_bridge_width 0.5)
			(island_removal_mode 0)
		)
		(polygon
			(pts
				(arc
					(start 340.424008 7.571994)
					(mid 340.805008 7.190994)
					(end 341.186008 7.571994)
				)
				(arc
					(start 341.186008 8.435594)
					(mid 340.805008 8.816594)
					(end 340.424008 8.435594)
				)
			)
		)
	)
	(zone
		(layers "F.Cu" "B.Cu" "In1.Cu" "In2.Cu" "In3.Cu" "In4.Cu" "In5.Cu" "In6.Cu"
			"In7.Cu" "In8.Cu" "In9.Cu" "In10.Cu" "In11.Cu" "In12.Cu" "In13.Cu" "In14.Cu"
			"In15.Cu" "In16.Cu"
		)
		(hatch none 0.5)
		(connect_pads
			(clearance 0)
		)
		(min_thickness 0.25)
		(keepout
			(tracks not_allowed)
			(vias allowed)
			(pads allowed)
			(copperpour not_allowed)
			(footprints allowed)
		)
		(placement
			(enabled no)
			(sheetname "")
		)
		(fill
			(thermal_gap 0.5)
			(thermal_bridge_width 0.5)
			(island_removal_mode 0)
		)
		(polygon
			(pts
				(arc
					(start 342.992964 -221.133924)
					(mid 342.335104 -221.133924)
					(end 342.992964 -221.133924)
				)
			)
		)
	)
	(zone
		(layers "F.Cu" "B.Cu" "In1.Cu" "In2.Cu" "In3.Cu" "In4.Cu" "In5.Cu" "In6.Cu"
			"In7.Cu" "In8.Cu" "In9.Cu" "In10.Cu" "In11.Cu" "In12.Cu" "In13.Cu" "In14.Cu"
			"In15.Cu" "In16.Cu"
		)
		(hatch none 0.5)
		(connect_pads
			(clearance 0)
		)
		(min_thickness 0.25)
		(keepout
			(tracks not_allowed)
			(vias allowed)
			(pads allowed)
			(copperpour not_allowed)
			(footprints allowed)
		)
		(placement
			(enabled no)
			(sheetname "")
		)
		(fill
			(thermal_gap 0.5)
			(thermal_bridge_width 0.5)
			(island_removal_mode 0)
		)
		(polygon
			(pts
				(arc
					(start 97.794064 -280.778204)
					(mid 98.451924 -280.778204)
					(end 97.794064 -280.778204)
				)
			)
		)
	)
	(zone
		(layers "F.Cu" "B.Cu" "In1.Cu" "In2.Cu" "In3.Cu" "In4.Cu" "In5.Cu" "In6.Cu"
			"In7.Cu" "In8.Cu" "In9.Cu" "In10.Cu" "In11.Cu" "In12.Cu" "In13.Cu" "In14.Cu"
			"In15.Cu" "In16.Cu"
		)
		(hatch none 0.5)
		(connect_pads
			(clearance 0)
		)
		(min_thickness 0.25)
		(keepout
			(tracks not_allowed)
			(vias allowed)
			(pads allowed)
			(copperpour not_allowed)
			(footprints allowed)
		)
		(placement
			(enabled no)
			(sheetname "")
		)
		(fill
			(thermal_gap 0.5)
			(thermal_bridge_width 0.5)
			(island_removal_mode 0)
		)
		(polygon
			(pts
				(arc
					(start 116.509292 -217.97645)
					(mid 116.528976 -217.92904)
					(end 116.535708 -217.878152)
				)
				(arc
					(start 116.535708 -217.878152)
					(mid 116.478052 -217.738958)
					(end 116.338858 -217.681302)
				)
				(arc
					(start 116.338858 -217.681302)
					(mid 116.240427 -217.707718)
					(end 116.168424 -217.779854)
				)
				(arc
					(start 115.698778 -218.593924)
					(mid 115.679094 -218.641334)
					(end 115.672362 -218.692222)
				)
				(arc
					(start 115.672362 -218.692222)
					(mid 115.730018 -218.831416)
					(end 115.869212 -218.889072)
				)
				(arc
					(start 115.869212 -218.889072)
					(mid 115.967643 -218.862656)
					(end 116.039646 -218.79052)
				)
			)
		)
	)
	(zone
		(layers "F.Cu" "B.Cu" "In1.Cu" "In2.Cu" "In3.Cu" "In4.Cu" "In5.Cu" "In6.Cu"
			"In7.Cu" "In8.Cu" "In9.Cu" "In10.Cu" "In11.Cu" "In12.Cu" "In13.Cu" "In14.Cu"
			"In15.Cu" "In16.Cu"
		)
		(hatch none 0.5)
		(connect_pads
			(clearance 0)
		)
		(min_thickness 0.25)
		(keepout
			(tracks not_allowed)
			(vias allowed)
			(pads allowed)
			(copperpour not_allowed)
			(footprints allowed)
		)
		(placement
			(enabled no)
			(sheetname "")
		)
		(fill
			(thermal_gap 0.5)
			(thermal_bridge_width 0.5)
			(island_removal_mode 0)
		)
		(polygon
			(pts
				(arc
					(start 102.023418 -283.219906)
					(mid 102.681278 -283.219906)
					(end 102.023418 -283.219906)
				)
			)
		)
	)
	(zone
		(layers "F.Cu" "B.Cu" "In1.Cu" "In2.Cu" "In3.Cu" "In4.Cu" "In5.Cu" "In6.Cu"
			"In7.Cu" "In8.Cu" "In9.Cu" "In10.Cu" "In11.Cu" "In12.Cu" "In13.Cu" "In14.Cu"
			"In15.Cu" "In16.Cu"
		)
		(hatch none 0.5)
		(connect_pads
			(clearance 0)
		)
		(min_thickness 0.25)
		(keepout
			(tracks not_allowed)
			(vias allowed)
			(pads allowed)
			(copperpour not_allowed)
			(footprints allowed)
		)
		(placement
			(enabled no)
			(sheetname "")
		)
		(fill
			(thermal_gap 0.5)
			(thermal_bridge_width 0.5)
			(island_removal_mode 0)
		)
		(polygon
			(pts
				(arc
					(start 376.465592 -285.661354)
					(mid 375.807732 -285.661354)
					(end 376.465592 -285.661354)
				)
			)
		)
	)
	(zone
		(layers "F.Cu" "B.Cu" "In1.Cu" "In2.Cu" "In3.Cu" "In4.Cu" "In5.Cu" "In6.Cu"
			"In7.Cu" "In8.Cu" "In9.Cu" "In10.Cu" "In11.Cu" "In12.Cu" "In13.Cu" "In14.Cu"
			"In15.Cu" "In16.Cu"
		)
		(hatch none 0.5)
		(connect_pads
			(clearance 0)
		)
		(min_thickness 0.25)
		(keepout
			(tracks not_allowed)
			(vias allowed)
			(pads allowed)
			(copperpour not_allowed)
			(footprints allowed)
		)
		(placement
			(enabled no)
			(sheetname "")
		)
		(fill
			(thermal_gap 0.5)
			(thermal_bridge_width 0.5)
			(island_removal_mode 0)
		)
		(polygon
			(pts
				(arc
					(start 183.271414 2.4892)
					(mid 183.652414 2.1082)
					(end 184.033414 2.4892)
				)
				(arc
					(start 184.033414 3.3528)
					(mid 183.652414 3.7338)
					(end 183.271414 3.3528)
				)
			)
		)
	)
	(zone
		(layers "F.Cu" "B.Cu" "In1.Cu" "In2.Cu" "In3.Cu" "In4.Cu" "In5.Cu" "In6.Cu"
			"In7.Cu" "In8.Cu" "In9.Cu" "In10.Cu" "In11.Cu" "In12.Cu" "In13.Cu" "In14.Cu"
			"In15.Cu" "In16.Cu"
		)
		(hatch none 0.5)
		(connect_pads
			(clearance 0)
		)
		(min_thickness 0.25)
		(keepout
			(tracks not_allowed)
			(vias allowed)
			(pads allowed)
			(copperpour not_allowed)
			(footprints allowed)
		)
		(placement
			(enabled no)
			(sheetname "")
		)
		(fill
			(thermal_gap 0.5)
			(thermal_bridge_width 0.5)
			(island_removal_mode 0)
		)
		(polygon
			(pts
				(arc
					(start 114.318542 -225.203258)
					(mid 113.660682 -225.203258)
					(end 114.318542 -225.203258)
				)
			)
		)
	)
	(zone
		(layers "F.Cu" "B.Cu" "In1.Cu" "In2.Cu" "In3.Cu" "In4.Cu" "In5.Cu" "In6.Cu"
			"In7.Cu" "In8.Cu" "In9.Cu" "In10.Cu" "In11.Cu" "In12.Cu" "In13.Cu" "In14.Cu"
			"In15.Cu" "In16.Cu"
		)
		(hatch none 0.5)
		(connect_pads
			(clearance 0)
		)
		(min_thickness 0.25)
		(keepout
			(tracks not_allowed)
			(vias allowed)
			(pads allowed)
			(copperpour not_allowed)
			(footprints allowed)
		)
		(placement
			(enabled no)
			(sheetname "")
		)
		(fill
			(thermal_gap 0.5)
			(thermal_bridge_width 0.5)
			(island_removal_mode 0)
		)
		(polygon
			(pts
				(arc
					(start 87.955628 -282.307538)
					(mid 87.883639 -282.235379)
					(end 87.785194 -282.208986)
				)
				(arc
					(start 87.785194 -282.208986)
					(mid 87.646 -282.266642)
					(end 87.588344 -282.405836)
				)
				(arc
					(start 87.588344 -282.405836)
					(mid 87.595101 -282.456717)
					(end 87.61476 -282.504134)
				)
				(arc
					(start 88.08466 -283.318204)
					(mid 88.156649 -283.390363)
					(end 88.255094 -283.416756)
				)
				(arc
					(start 88.255094 -283.416756)
					(mid 88.394288 -283.3591)
					(end 88.451944 -283.219906)
				)
				(arc
					(start 88.451944 -283.219906)
					(mid 88.445187 -283.169025)
					(end 88.425528 -283.121608)
				)
			)
		)
	)
	(zone
		(layers "F.Cu" "B.Cu" "In1.Cu" "In2.Cu" "In3.Cu" "In4.Cu" "In5.Cu" "In6.Cu"
			"In7.Cu" "In8.Cu" "In9.Cu" "In10.Cu" "In11.Cu" "In12.Cu" "In13.Cu" "In14.Cu"
			"In15.Cu" "In16.Cu"
		)
		(hatch none 0.5)
		(connect_pads
			(clearance 0)
		)
		(min_thickness 0.25)
		(keepout
			(tracks not_allowed)
			(vias allowed)
			(pads allowed)
			(copperpour not_allowed)
			(footprints allowed)
		)
		(placement
			(enabled no)
			(sheetname "")
		)
		(fill
			(thermal_gap 0.5)
			(thermal_bridge_width 0.5)
			(island_removal_mode 0)
		)
		(polygon
			(pts
				(arc
					(start 366.01781 -225.203258)
					(mid 365.35995 -225.203258)
					(end 366.01781 -225.203258)
				)
			)
		)
	)
	(zone
		(layers "F.Cu" "B.Cu" "In1.Cu" "In2.Cu" "In3.Cu" "In4.Cu" "In5.Cu" "In6.Cu"
			"In7.Cu" "In8.Cu" "In9.Cu" "In10.Cu" "In11.Cu" "In12.Cu" "In13.Cu" "In14.Cu"
			"In15.Cu" "In16.Cu"
		)
		(hatch none 0.5)
		(connect_pads
			(clearance 0)
		)
		(min_thickness 0.25)
		(keepout
			(tracks not_allowed)
			(vias allowed)
			(pads allowed)
			(copperpour not_allowed)
			(footprints allowed)
		)
		(placement
			(enabled no)
			(sheetname "")
		)
		(fill
			(thermal_gap 0.5)
			(thermal_bridge_width 0.5)
			(island_removal_mode 0)
		)
		(polygon
			(pts
				(arc
					(start 133.896354 -216.966292)
					(mid 133.824365 -216.894133)
					(end 133.72592 -216.86774)
				)
				(arc
					(start 133.72592 -216.86774)
					(mid 133.586726 -216.925396)
					(end 133.52907 -217.06459)
				)
				(arc
					(start 133.52907 -217.06459)
					(mid 133.535827 -217.115471)
					(end 133.555486 -217.162888)
				)
				(arc
					(start 134.025132 -217.976704)
					(mid 134.097121 -218.048863)
					(end 134.195566 -218.075256)
				)
				(arc
					(start 134.195566 -218.075256)
					(mid 134.33476 -218.0176)
					(end 134.392416 -217.878406)
				)
				(arc
					(start 134.392416 -217.878406)
					(mid 134.385659 -217.827525)
					(end 134.366 -217.780108)
				)
			)
		)
	)
	(zone
		(layers "F.Cu" "B.Cu" "In1.Cu" "In2.Cu" "In3.Cu" "In4.Cu" "In5.Cu" "In6.Cu"
			"In7.Cu" "In8.Cu" "In9.Cu" "In10.Cu" "In11.Cu" "In12.Cu" "In13.Cu" "In14.Cu"
			"In15.Cu" "In16.Cu"
		)
		(hatch none 0.5)
		(connect_pads
			(clearance 0)
		)
		(min_thickness 0.25)
		(keepout
			(tracks not_allowed)
			(vias allowed)
			(pads allowed)
			(copperpour not_allowed)
			(footprints allowed)
		)
		(placement
			(enabled no)
			(sheetname "")
		)
		(fill
			(thermal_gap 0.5)
			(thermal_bridge_width 0.5)
			(island_removal_mode 0)
		)
		(polygon
			(pts
				(arc
					(start 381.836422 -216.966292)
					(mid 381.764433 -216.894133)
					(end 381.665988 -216.86774)
				)
				(arc
					(start 381.665988 -216.86774)
					(mid 381.526794 -216.925396)
					(end 381.469138 -217.06459)
				)
				(arc
					(start 381.469138 -217.06459)
					(mid 381.475895 -217.115471)
					(end 381.495554 -217.162888)
				)
				(arc
					(start 381.9652 -217.976704)
					(mid 382.037189 -218.048863)
					(end 382.135634 -218.075256)
				)
				(arc
					(start 382.135634 -218.075256)
					(mid 382.274828 -218.0176)
					(end 382.332484 -217.878406)
				)
				(arc
					(start 382.332484 -217.878406)
					(mid 382.325727 -217.827525)
					(end 382.306068 -217.780108)
				)
			)
		)
	)
	(zone
		(layers "F.Cu" "B.Cu" "In1.Cu" "In2.Cu" "In3.Cu" "In4.Cu" "In5.Cu" "In6.Cu"
			"In7.Cu" "In8.Cu" "In9.Cu" "In10.Cu" "In11.Cu" "In12.Cu" "In13.Cu" "In14.Cu"
			"In15.Cu" "In16.Cu"
		)
		(hatch none 0.5)
		(connect_pads
			(clearance 0)
		)
		(min_thickness 0.25)
		(keepout
			(tracks not_allowed)
			(vias allowed)
			(pads allowed)
			(copperpour not_allowed)
			(footprints allowed)
		)
		(placement
			(enabled no)
			(sheetname "")
		)
		(fill
			(thermal_gap 0.5)
			(thermal_bridge_width 0.5)
			(island_removal_mode 0)
		)
		(polygon
			(pts
				(arc
					(start 122.118882 -220.319854)
					(mid 122.776742 -220.319854)
					(end 122.118882 -220.319854)
				)
			)
		)
	)
	(zone
		(layers "F.Cu" "B.Cu" "In1.Cu" "In2.Cu" "In3.Cu" "In4.Cu" "In5.Cu" "In6.Cu"
			"In7.Cu" "In8.Cu" "In9.Cu" "In10.Cu" "In11.Cu" "In12.Cu" "In13.Cu" "In14.Cu"
			"In15.Cu" "In16.Cu"
		)
		(hatch none 0.5)
		(connect_pads
			(clearance 0)
		)
		(min_thickness 0.25)
		(keepout
			(tracks not_allowed)
			(vias allowed)
			(pads allowed)
			(copperpour not_allowed)
			(footprints allowed)
		)
		(placement
			(enabled no)
			(sheetname "")
		)
		(fill
			(thermal_gap 0.5)
			(thermal_bridge_width 0.5)
			(island_removal_mode 0)
		)
		(polygon
			(pts
				(arc
					(start 113.220754 -216.966292)
					(mid 113.148765 -216.894133)
					(end 113.05032 -216.86774)
				)
				(arc
					(start 113.05032 -216.86774)
					(mid 112.911126 -216.925396)
					(end 112.85347 -217.06459)
				)
				(arc
					(start 112.85347 -217.06459)
					(mid 112.860227 -217.115471)
					(end 112.879886 -217.162888)
				)
				(arc
					(start 113.349532 -217.976704)
					(mid 113.421521 -218.048863)
					(end 113.519966 -218.075256)
				)
				(arc
					(start 113.519966 -218.075256)
					(mid 113.65916 -218.0176)
					(end 113.716816 -217.878406)
				)
				(arc
					(start 113.716816 -217.878406)
					(mid 113.710059 -217.827525)
					(end 113.6904 -217.780108)
				)
			)
		)
	)
	(zone
		(layers "F.Cu" "B.Cu" "In1.Cu" "In2.Cu" "In3.Cu" "In4.Cu" "In5.Cu" "In6.Cu"
			"In7.Cu" "In8.Cu" "In9.Cu" "In10.Cu" "In11.Cu" "In12.Cu" "In13.Cu" "In14.Cu"
			"In15.Cu" "In16.Cu"
		)
		(hatch none 0.5)
		(connect_pads
			(clearance 0)
		)
		(min_thickness 0.25)
		(keepout
			(tracks not_allowed)
			(vias allowed)
			(pads allowed)
			(copperpour not_allowed)
			(footprints allowed)
		)
		(placement
			(enabled no)
			(sheetname "")
		)
		(fill
			(thermal_gap 0.5)
			(thermal_bridge_width 0.5)
			(island_removal_mode 0)
		)
		(polygon
			(pts
				(arc
					(start 98.922078 -288.103056)
					(mid 98.264218 -288.103056)
					(end 98.922078 -288.103056)
				)
			)
		)
	)
	(zone
		(layers "F.Cu" "B.Cu" "In1.Cu" "In2.Cu" "In3.Cu" "In4.Cu" "In5.Cu" "In6.Cu"
			"In7.Cu" "In8.Cu" "In9.Cu" "In10.Cu" "In11.Cu" "In12.Cu" "In13.Cu" "In14.Cu"
			"In15.Cu" "In16.Cu"
		)
		(hatch none 0.5)
		(connect_pads
			(clearance 0)
		)
		(min_thickness 0.25)
		(keepout
			(tracks not_allowed)
			(vias allowed)
			(pads allowed)
			(copperpour not_allowed)
			(footprints allowed)
		)
		(placement
			(enabled no)
			(sheetname "")
		)
		(fill
			(thermal_gap 0.5)
			(thermal_bridge_width 0.5)
			(island_removal_mode 0)
		)
		(polygon
			(pts
				(arc
					(start 368.477546 -286.475424)
					(mid 367.819686 -286.475424)
					(end 368.477546 -286.475424)
				)
			)
		)
	)
	(zone
		(layers "F.Cu" "B.Cu" "In1.Cu" "In2.Cu" "In3.Cu" "In4.Cu" "In5.Cu" "In6.Cu"
			"In7.Cu" "In8.Cu" "In9.Cu" "In10.Cu" "In11.Cu" "In12.Cu" "In13.Cu" "In14.Cu"
			"In15.Cu" "In16.Cu"
		)
		(hatch none 0.5)
		(connect_pads
			(clearance 0)
		)
		(min_thickness 0.25)
		(keepout
			(tracks not_allowed)
			(vias allowed)
			(pads allowed)
			(copperpour not_allowed)
			(footprints allowed)
		)
		(placement
			(enabled no)
			(sheetname "")
		)
		(fill
			(thermal_gap 0.5)
			(thermal_bridge_width 0.5)
			(island_removal_mode 0)
		)
		(polygon
			(pts
				(arc
					(start 381.95885 -406.62352)
					(mid 381.57785 -407.00452)
					(end 381.95885 -407.38552)
				)
				(arc
					(start 382.82245 -407.38552)
					(mid 383.20345 -407.00452)
					(end 382.82245 -406.62352)
				)
			)
		)
	)
	(zone
		(layers "F.Cu" "B.Cu" "In1.Cu" "In2.Cu" "In3.Cu" "In4.Cu" "In5.Cu" "In6.Cu"
			"In7.Cu" "In8.Cu" "In9.Cu" "In10.Cu" "In11.Cu" "In12.Cu" "In13.Cu" "In14.Cu"
			"In15.Cu" "In16.Cu"
		)
		(hatch none 0.5)
		(connect_pads
			(clearance 0)
		)
		(min_thickness 0.25)
		(keepout
			(tracks not_allowed)
			(vias allowed)
			(pads allowed)
			(copperpour not_allowed)
			(footprints allowed)
		)
		(placement
			(enabled no)
			(sheetname "")
		)
		(fill
			(thermal_gap 0.5)
			(thermal_bridge_width 0.5)
			(island_removal_mode 0)
		)
		(polygon
			(pts
				(arc
					(start 102.4128 -224.291144)
					(mid 102.340811 -224.218985)
					(end 102.242366 -224.192592)
				)
				(arc
					(start 102.242366 -224.192592)
					(mid 102.103172 -224.250248)
					(end 102.045516 -224.389442)
				)
				(arc
					(start 102.045516 -224.389442)
					(mid 102.052273 -224.440323)
					(end 102.071932 -224.48774)
				)
				(arc
					(start 102.541578 -225.301556)
					(mid 102.613567 -225.373715)
					(end 102.712012 -225.400108)
				)
				(arc
					(start 102.712012 -225.400108)
					(mid 102.851206 -225.342452)
					(end 102.908862 -225.203258)
				)
				(arc
					(start 102.908862 -225.203258)
					(mid 102.902105 -225.152377)
					(end 102.882446 -225.10496)
				)
			)
		)
	)
	(zone
		(layers "F.Cu" "B.Cu" "In1.Cu" "In2.Cu" "In3.Cu" "In4.Cu" "In5.Cu" "In6.Cu"
			"In7.Cu" "In8.Cu" "In9.Cu" "In10.Cu" "In11.Cu" "In12.Cu" "In13.Cu" "In14.Cu"
			"In15.Cu" "In16.Cu"
		)
		(hatch none 0.5)
		(connect_pads
			(clearance 0)
		)
		(min_thickness 0.25)
		(keepout
			(tracks not_allowed)
			(vias allowed)
			(pads allowed)
			(copperpour not_allowed)
			(footprints allowed)
		)
		(placement
			(enabled no)
			(sheetname "")
		)
		(fill
			(thermal_gap 0.5)
			(thermal_bridge_width 0.5)
			(island_removal_mode 0)
		)
		(polygon
			(pts
				(arc
					(start 96.462342 -217.064336)
					(mid 95.804482 -217.064336)
					(end 96.462342 -217.064336)
				)
			)
		)
	)
	(zone
		(layers "F.Cu" "B.Cu" "In1.Cu" "In2.Cu" "In3.Cu" "In4.Cu" "In5.Cu" "In6.Cu"
			"In7.Cu" "In8.Cu" "In9.Cu" "In10.Cu" "In11.Cu" "In12.Cu" "In13.Cu" "In14.Cu"
			"In15.Cu" "In16.Cu"
		)
		(hatch none 0.5)
		(connect_pads
			(clearance 0)
		)
		(min_thickness 0.25)
		(keepout
			(tracks not_allowed)
			(vias allowed)
			(pads allowed)
			(copperpour not_allowed)
			(footprints allowed)
		)
		(placement
			(enabled no)
			(sheetname "")
		)
		(fill
			(thermal_gap 0.5)
			(thermal_bridge_width 0.5)
			(island_removal_mode 0)
		)
		(polygon
			(pts
				(arc
					(start 357.401114 -217.162634)
					(mid 357.420798 -217.115224)
					(end 357.42753 -217.064336)
				)
				(arc
					(start 357.42753 -217.064336)
					(mid 357.369874 -216.925142)
					(end 357.23068 -216.867486)
				)
				(arc
					(start 357.23068 -216.867486)
					(mid 357.132249 -216.893902)
					(end 357.060246 -216.966038)
				)
				(arc
					(start 356.5906 -217.780108)
					(mid 356.570916 -217.827518)
					(end 356.564184 -217.878406)
				)
				(arc
					(start 356.564184 -217.878406)
					(mid 356.62184 -218.0176)
					(end 356.761034 -218.075256)
				)
				(arc
					(start 356.761034 -218.075256)
					(mid 356.859465 -218.04884)
					(end 356.931468 -217.976704)
				)
			)
		)
	)
	(zone
		(layers "F.Cu" "B.Cu" "In1.Cu" "In2.Cu" "In3.Cu" "In4.Cu" "In5.Cu" "In6.Cu"
			"In7.Cu" "In8.Cu" "In9.Cu" "In10.Cu" "In11.Cu" "In12.Cu" "In13.Cu" "In14.Cu"
			"In15.Cu" "In16.Cu"
		)
		(hatch none 0.5)
		(connect_pads
			(clearance 0)
		)
		(min_thickness 0.25)
		(keepout
			(tracks not_allowed)
			(vias allowed)
			(pads allowed)
			(copperpour not_allowed)
			(footprints allowed)
		)
		(placement
			(enabled no)
			(sheetname "")
		)
		(fill
			(thermal_gap 0.5)
			(thermal_bridge_width 0.5)
			(island_removal_mode 0)
		)
		(polygon
			(pts
				(arc
					(start 377.875292 -289.807142)
					(mid 377.217432 -289.807142)
					(end 377.875292 -289.807142)
				)
			)
		)
	)
	(zone
		(layers "F.Cu" "B.Cu" "In1.Cu" "In2.Cu" "In3.Cu" "In4.Cu" "In5.Cu" "In6.Cu"
			"In7.Cu" "In8.Cu" "In9.Cu" "In10.Cu" "In11.Cu" "In12.Cu" "In13.Cu" "In14.Cu"
			"In15.Cu" "In16.Cu"
		)
		(hatch none 0.5)
		(connect_pads
			(clearance 0)
		)
		(min_thickness 0.25)
		(keepout
			(tracks not_allowed)
			(vias allowed)
			(pads allowed)
			(copperpour not_allowed)
			(footprints allowed)
		)
		(placement
			(enabled no)
			(sheetname "")
		)
		(fill
			(thermal_gap 0.5)
			(thermal_bridge_width 0.5)
			(island_removal_mode 0)
		)
		(polygon
			(pts
				(arc
					(start 128.257046 -223.67367)
					(mid 128.27673 -223.62626)
					(end 128.283462 -223.575372)
				)
				(arc
					(start 128.283462 -223.575372)
					(mid 128.225806 -223.436178)
					(end 128.086612 -223.378522)
				)
				(arc
					(start 128.086612 -223.378522)
					(mid 127.988181 -223.404938)
					(end 127.916178 -223.477074)
				)
				(arc
					(start 127.446532 -224.291144)
					(mid 127.426848 -224.338554)
					(end 127.420116 -224.389442)
				)
				(arc
					(start 127.420116 -224.389442)
					(mid 127.477772 -224.528636)
					(end 127.616966 -224.586292)
				)
				(arc
					(start 127.616966 -224.586292)
					(mid 127.715397 -224.559876)
					(end 127.7874 -224.48774)
				)
			)
		)
	)
	(zone
		(layers "F.Cu" "B.Cu" "In1.Cu" "In2.Cu" "In3.Cu" "In4.Cu" "In5.Cu" "In6.Cu"
			"In7.Cu" "In8.Cu" "In9.Cu" "In10.Cu" "In11.Cu" "In12.Cu" "In13.Cu" "In14.Cu"
			"In15.Cu" "In16.Cu"
		)
		(hatch none 0.5)
		(connect_pads
			(clearance 0)
		)
		(min_thickness 0.25)
		(keepout
			(tracks not_allowed)
			(vias allowed)
			(pads allowed)
			(copperpour not_allowed)
			(footprints allowed)
		)
		(placement
			(enabled no)
			(sheetname "")
		)
		(fill
			(thermal_gap 0.5)
			(thermal_bridge_width 0.5)
			(island_removal_mode 0)
		)
		(polygon
			(pts
				(arc
					(start 93.594682 -285.563056)
					(mid 93.522693 -285.490897)
					(end 93.424248 -285.464504)
				)
				(arc
					(start 93.424248 -285.464504)
					(mid 93.285054 -285.52216)
					(end 93.227398 -285.661354)
				)
				(arc
					(start 93.227398 -285.661354)
					(mid 93.234155 -285.712235)
					(end 93.253814 -285.759652)
				)
				(arc
					(start 93.723714 -286.573722)
					(mid 93.795703 -286.645881)
					(end 93.894148 -286.672274)
				)
				(arc
					(start 93.894148 -286.672274)
					(mid 94.033342 -286.614618)
					(end 94.090998 -286.475424)
				)
				(arc
					(start 94.090998 -286.475424)
					(mid 94.084241 -286.424543)
					(end 94.064582 -286.377126)
				)
			)
		)
	)
	(zone
		(layers "F.Cu" "B.Cu" "In1.Cu" "In2.Cu" "In3.Cu" "In4.Cu" "In5.Cu" "In6.Cu"
			"In7.Cu" "In8.Cu" "In9.Cu" "In10.Cu" "In11.Cu" "In12.Cu" "In13.Cu" "In14.Cu"
			"In15.Cu" "In16.Cu"
		)
		(hatch none 0.5)
		(connect_pads
			(clearance 0)
		)
		(min_thickness 0.25)
		(keepout
			(tracks not_allowed)
			(vias allowed)
			(pads allowed)
			(copperpour not_allowed)
			(footprints allowed)
		)
		(placement
			(enabled no)
			(sheetname "")
		)
		(fill
			(thermal_gap 0.5)
			(thermal_bridge_width 0.5)
			(island_removal_mode 0)
		)
		(polygon
			(pts
				(arc
					(start 346.391992 -285.661354)
					(mid 345.734132 -285.661354)
					(end 346.391992 -285.661354)
				)
			)
		)
	)
	(zone
		(layers "F.Cu" "B.Cu" "In1.Cu" "In2.Cu" "In3.Cu" "In4.Cu" "In5.Cu" "In6.Cu"
			"In7.Cu" "In8.Cu" "In9.Cu" "In10.Cu" "In11.Cu" "In12.Cu" "In13.Cu" "In14.Cu"
			"In15.Cu" "In16.Cu"
		)
		(hatch none 0.5)
		(connect_pads
			(clearance 0)
		)
		(min_thickness 0.25)
		(keepout
			(tracks not_allowed)
			(vias allowed)
			(pads allowed)
			(copperpour not_allowed)
			(footprints allowed)
		)
		(placement
			(enabled no)
			(sheetname "")
		)
		(fill
			(thermal_gap 0.5)
			(thermal_bridge_width 0.5)
			(island_removal_mode 0)
		)
		(polygon
			(pts
				(arc
					(start 350.04121 -220.319854)
					(mid 349.38335 -220.319854)
					(end 350.04121 -220.319854)
				)
			)
		)
	)
	(zone
		(layers "F.Cu" "B.Cu" "In1.Cu" "In2.Cu" "In3.Cu" "In4.Cu" "In5.Cu" "In6.Cu"
			"In7.Cu" "In8.Cu" "In9.Cu" "In10.Cu" "In11.Cu" "In12.Cu" "In13.Cu" "In14.Cu"
			"In15.Cu" "In16.Cu"
		)
		(hatch none 0.5)
		(connect_pads
			(clearance 0)
		)
		(min_thickness 0.25)
		(keepout
			(tracks not_allowed)
			(vias allowed)
			(pads allowed)
			(copperpour not_allowed)
			(footprints allowed)
		)
		(placement
			(enabled no)
			(sheetname "")
		)
		(fill
			(thermal_gap 0.5)
			(thermal_bridge_width 0.5)
			(island_removal_mode 0)
		)
		(polygon
			(pts
				(arc
					(start 352.030792 -285.661354)
					(mid 351.372932 -285.661354)
					(end 352.030792 -285.661354)
				)
			)
		)
	)
	(zone
		(layers "F.Cu" "B.Cu" "In1.Cu" "In2.Cu" "In3.Cu" "In4.Cu" "In5.Cu" "In6.Cu"
			"In7.Cu" "In8.Cu" "In9.Cu" "In10.Cu" "In11.Cu" "In12.Cu" "In13.Cu" "In14.Cu"
			"In15.Cu" "In16.Cu"
		)
		(hatch none 0.5)
		(connect_pads
			(clearance 0)
		)
		(min_thickness 0.25)
		(keepout
			(tracks not_allowed)
			(vias allowed)
			(pads allowed)
			(copperpour not_allowed)
			(footprints allowed)
		)
		(placement
			(enabled no)
			(sheetname "")
		)
		(fill
			(thermal_gap 0.5)
			(thermal_bridge_width 0.5)
			(island_removal_mode 0)
		)
		(polygon
			(pts
				(arc
					(start 406.46477 -409.649168)
					(mid 406.08377 -410.030168)
					(end 406.46477 -410.411168)
				)
				(arc
					(start 407.32837 -410.411168)
					(mid 407.70937 -410.030168)
					(end 407.32837 -409.649168)
				)
			)
		)
	)
	(zone
		(layers "F.Cu" "B.Cu" "In1.Cu" "In2.Cu" "In3.Cu" "In4.Cu" "In5.Cu" "In6.Cu"
			"In7.Cu" "In8.Cu" "In9.Cu" "In10.Cu" "In11.Cu" "In12.Cu" "In13.Cu" "In14.Cu"
			"In15.Cu" "In16.Cu"
		)
		(hatch none 0.5)
		(connect_pads
			(clearance 0)
		)
		(min_thickness 0.25)
		(keepout
			(tracks not_allowed)
			(vias allowed)
			(pads allowed)
			(copperpour not_allowed)
			(footprints allowed)
		)
		(placement
			(enabled no)
			(sheetname "")
		)
		(fill
			(thermal_gap 0.5)
			(thermal_bridge_width 0.5)
			(island_removal_mode 0)
		)
		(polygon
			(pts
				(arc
					(start 100.063046 -223.67367)
					(mid 100.08273 -223.62626)
					(end 100.089462 -223.575372)
				)
				(arc
					(start 100.089462 -223.575372)
					(mid 100.031806 -223.436178)
					(end 99.892612 -223.378522)
				)
				(arc
					(start 99.892612 -223.378522)
					(mid 99.794181 -223.404938)
					(end 99.722178 -223.477074)
				)
				(arc
					(start 99.252532 -224.291144)
					(mid 99.232848 -224.338554)
					(end 99.226116 -224.389442)
				)
				(arc
					(start 99.226116 -224.389442)
					(mid 99.283772 -224.528636)
					(end 99.422966 -224.586292)
				)
				(arc
					(start 99.422966 -224.586292)
					(mid 99.521397 -224.559876)
					(end 99.5934 -224.48774)
				)
			)
		)
	)
	(zone
		(layers "F.Cu" "B.Cu" "In1.Cu" "In2.Cu" "In3.Cu" "In4.Cu" "In5.Cu" "In6.Cu"
			"In7.Cu" "In8.Cu" "In9.Cu" "In10.Cu" "In11.Cu" "In12.Cu" "In13.Cu" "In14.Cu"
			"In15.Cu" "In16.Cu"
		)
		(hatch none 0.5)
		(connect_pads
			(clearance 0)
		)
		(min_thickness 0.25)
		(keepout
			(tracks not_allowed)
			(vias allowed)
			(pads allowed)
			(copperpour not_allowed)
			(footprints allowed)
		)
		(placement
			(enabled no)
			(sheetname "")
		)
		(fill
			(thermal_gap 0.5)
			(thermal_bridge_width 0.5)
			(island_removal_mode 0)
		)
		(polygon
			(pts
				(arc
					(start 340.173564 -217.878406)
					(mid 339.515704 -217.878406)
					(end 340.173564 -217.878406)
				)
			)
		)
	)
	(zone
		(layers "F.Cu" "B.Cu" "In1.Cu" "In2.Cu" "In3.Cu" "In4.Cu" "In5.Cu" "In6.Cu"
			"In7.Cu" "In8.Cu" "In9.Cu" "In10.Cu" "In11.Cu" "In12.Cu" "In13.Cu" "In14.Cu"
			"In15.Cu" "In16.Cu"
		)
		(hatch none 0.5)
		(connect_pads
			(clearance 0)
		)
		(min_thickness 0.25)
		(keepout
			(tracks not_allowed)
			(vias allowed)
			(pads allowed)
			(copperpour not_allowed)
			(footprints allowed)
		)
		(placement
			(enabled no)
			(sheetname "")
		)
		(fill
			(thermal_gap 0.5)
			(thermal_bridge_width 0.5)
			(island_removal_mode 0)
		)
		(polygon
			(pts
				(arc
					(start 120.427496 -217.878406)
					(mid 119.769636 -217.878406)
					(end 120.427496 -217.878406)
				)
			)
		)
	)
	(zone
		(layers "F.Cu" "B.Cu" "In1.Cu" "In2.Cu" "In3.Cu" "In4.Cu" "In5.Cu" "In6.Cu"
			"In7.Cu" "In8.Cu" "In9.Cu" "In10.Cu" "In11.Cu" "In12.Cu" "In13.Cu" "In14.Cu"
			"In15.Cu" "In16.Cu"
		)
		(hatch none 0.5)
		(connect_pads
			(clearance 0)
		)
		(min_thickness 0.25)
		(keepout
			(tracks not_allowed)
			(vias allowed)
			(pads allowed)
			(copperpour not_allowed)
			(footprints allowed)
		)
		(placement
			(enabled no)
			(sheetname "")
		)
		(fill
			(thermal_gap 0.5)
			(thermal_bridge_width 0.5)
			(island_removal_mode 0)
		)
		(polygon
			(pts
				(arc
					(start 122.307096 -217.878406)
					(mid 121.649236 -217.878406)
					(end 122.307096 -217.878406)
				)
			)
		)
	)
	(zone
		(layers "F.Cu" "B.Cu" "In1.Cu" "In2.Cu" "In3.Cu" "In4.Cu" "In5.Cu" "In6.Cu"
			"In7.Cu" "In8.Cu" "In9.Cu" "In10.Cu" "In11.Cu" "In12.Cu" "In13.Cu" "In14.Cu"
			"In15.Cu" "In16.Cu"
		)
		(hatch none 0.5)
		(connect_pads
			(clearance 0)
		)
		(min_thickness 0.25)
		(keepout
			(tracks not_allowed)
			(vias allowed)
			(pads allowed)
			(copperpour not_allowed)
			(footprints allowed)
		)
		(placement
			(enabled no)
			(sheetname "")
		)
		(fill
			(thermal_gap 0.5)
			(thermal_bridge_width 0.5)
			(island_removal_mode 0)
		)
		(polygon
			(pts
				(arc
					(start 126.377954 -220.22181)
					(mid 126.305965 -220.149651)
					(end 126.20752 -220.123258)
				)
				(arc
					(start 126.20752 -220.123258)
					(mid 126.068326 -220.180914)
					(end 126.01067 -220.320108)
				)
				(arc
					(start 126.01067 -220.320108)
					(mid 126.017427 -220.370989)
					(end 126.037086 -220.418406)
				)
				(arc
					(start 126.506732 -221.232222)
					(mid 126.578721 -221.304381)
					(end 126.677166 -221.330774)
				)
				(arc
					(start 126.677166 -221.330774)
					(mid 126.81636 -221.273118)
					(end 126.874016 -221.133924)
				)
				(arc
					(start 126.874016 -221.133924)
					(mid 126.867259 -221.083043)
					(end 126.8476 -221.035626)
				)
			)
		)
	)
	(zone
		(layers "F.Cu" "B.Cu" "In1.Cu" "In2.Cu" "In3.Cu" "In4.Cu" "In5.Cu" "In6.Cu"
			"In7.Cu" "In8.Cu" "In9.Cu" "In10.Cu" "In11.Cu" "In12.Cu" "In13.Cu" "In14.Cu"
			"In15.Cu" "In16.Cu"
		)
		(hatch none 0.5)
		(connect_pads
			(clearance 0)
		)
		(min_thickness 0.25)
		(keepout
			(tracks not_allowed)
			(vias allowed)
			(pads allowed)
			(copperpour not_allowed)
			(footprints allowed)
		)
		(placement
			(enabled no)
			(sheetname "")
		)
		(fill
			(thermal_gap 0.5)
			(thermal_bridge_width 0.5)
			(island_removal_mode 0)
		)
		(polygon
			(pts
				(arc
					(start 127.475742 -225.203258)
					(mid 126.817882 -225.203258)
					(end 127.475742 -225.203258)
				)
			)
		)
	)
	(zone
		(layers "F.Cu" "B.Cu" "In1.Cu" "In2.Cu" "In3.Cu" "In4.Cu" "In5.Cu" "In6.Cu"
			"In7.Cu" "In8.Cu" "In9.Cu" "In10.Cu" "In11.Cu" "In12.Cu" "In13.Cu" "In14.Cu"
			"In15.Cu" "In16.Cu"
		)
		(hatch none 0.5)
		(connect_pads
			(clearance 0)
		)
		(min_thickness 0.25)
		(keepout
			(tracks not_allowed)
			(vias allowed)
			(pads allowed)
			(copperpour not_allowed)
			(footprints allowed)
		)
		(placement
			(enabled no)
			(sheetname "")
		)
		(fill
			(thermal_gap 0.5)
			(thermal_bridge_width 0.5)
			(island_removal_mode 0)
		)
		(polygon
			(pts
				(arc
					(start 374.586246 -288.917126)
					(mid 373.928386 -288.917126)
					(end 374.586246 -288.917126)
				)
			)
		)
	)
	(zone
		(layers "F.Cu" "B.Cu" "In1.Cu" "In2.Cu" "In3.Cu" "In4.Cu" "In5.Cu" "In6.Cu"
			"In7.Cu" "In8.Cu" "In9.Cu" "In10.Cu" "In11.Cu" "In12.Cu" "In13.Cu" "In14.Cu"
			"In15.Cu" "In16.Cu"
		)
		(hatch none 0.5)
		(connect_pads
			(clearance 0)
		)
		(min_thickness 0.25)
		(keepout
			(tracks not_allowed)
			(vias allowed)
			(pads allowed)
			(copperpour not_allowed)
			(footprints allowed)
		)
		(placement
			(enabled no)
			(sheetname "")
		)
		(fill
			(thermal_gap 0.5)
			(thermal_bridge_width 0.5)
			(island_removal_mode 0)
		)
		(polygon
			(pts
				(arc
					(start 349.681546 -281.59202)
					(mid 349.023686 -281.59202)
					(end 349.681546 -281.59202)
				)
			)
		)
	)
	(zone
		(layers "F.Cu" "B.Cu" "In1.Cu" "In2.Cu" "In3.Cu" "In4.Cu" "In5.Cu" "In6.Cu"
			"In7.Cu" "In8.Cu" "In9.Cu" "In10.Cu" "In11.Cu" "In12.Cu" "In13.Cu" "In14.Cu"
			"In15.Cu" "In16.Cu"
		)
		(hatch none 0.5)
		(connect_pads
			(clearance 0)
		)
		(min_thickness 0.25)
		(keepout
			(tracks not_allowed)
			(vias allowed)
			(pads allowed)
			(copperpour not_allowed)
			(footprints allowed)
		)
		(placement
			(enabled no)
			(sheetname "")
		)
		(fill
			(thermal_gap 0.5)
			(thermal_bridge_width 0.5)
			(island_removal_mode 0)
		)
		(polygon
			(pts
				(xy 642.264146 -364.97514) (xy 642.264146 -359.975404) (xy 642.568946 -360.280204) (xy 642.568946 -364.67034)
			)
		)
	)
	(zone
		(layers "F.Cu" "B.Cu" "In1.Cu" "In2.Cu" "In3.Cu" "In4.Cu" "In5.Cu" "In6.Cu"
			"In7.Cu" "In8.Cu" "In9.Cu" "In10.Cu" "In11.Cu" "In12.Cu" "In13.Cu" "In14.Cu"
			"In15.Cu" "In16.Cu"
		)
		(hatch none 0.5)
		(connect_pads
			(clearance 0)
		)
		(min_thickness 0.25)
		(keepout
			(tracks not_allowed)
			(vias allowed)
			(pads allowed)
			(copperpour not_allowed)
			(footprints allowed)
		)
		(placement
			(enabled no)
			(sheetname "")
		)
		(fill
			(thermal_gap 0.5)
			(thermal_bridge_width 0.5)
			(island_removal_mode 0)
		)
		(polygon
			(pts
				(arc
					(start 90.65768 -213.646766)
					(mid 90.589972 -213.574915)
					(end 90.494866 -213.548468)
				)
				(arc
					(start 90.494866 -213.548468)
					(mid 90.364652 -213.602404)
					(end 90.310716 -213.732618)
				)
				(arc
					(start 90.310716 -213.732618)
					(mid 90.316167 -213.776839)
					(end 90.332052 -213.81847)
				)
				(arc
					(start 90.801444 -214.708486)
					(mid 90.869152 -214.780337)
					(end 90.964258 -214.806784)
				)
				(arc
					(start 90.964258 -214.806784)
					(mid 91.094472 -214.752848)
					(end 91.148408 -214.622634)
				)
				(arc
					(start 91.148408 -214.622634)
					(mid 91.142957 -214.578413)
					(end 91.127072 -214.536782)
				)
			)
		)
	)
	(zone
		(layers "F.Cu" "B.Cu" "In1.Cu" "In2.Cu" "In3.Cu" "In4.Cu" "In5.Cu" "In6.Cu"
			"In7.Cu" "In8.Cu" "In9.Cu" "In10.Cu" "In11.Cu" "In12.Cu" "In13.Cu" "In14.Cu"
			"In15.Cu" "In16.Cu"
		)
		(hatch none 0.5)
		(connect_pads
			(clearance 0)
		)
		(min_thickness 0.25)
		(keepout
			(tracks not_allowed)
			(vias allowed)
			(pads allowed)
			(copperpour not_allowed)
			(footprints allowed)
		)
		(placement
			(enabled no)
			(sheetname "")
		)
		(fill
			(thermal_gap 0.5)
			(thermal_bridge_width 0.5)
			(island_removal_mode 0)
		)
		(polygon
			(pts
				(arc
					(start 308.389528 -406.62352)
					(mid 308.008528 -407.00452)
					(end 308.389528 -407.38552)
				)
				(arc
					(start 309.253128 -407.38552)
					(mid 309.634128 -407.00452)
					(end 309.253128 -406.62352)
				)
			)
		)
	)
	(zone
		(layers "F.Cu" "B.Cu" "In1.Cu" "In2.Cu" "In3.Cu" "In4.Cu" "In5.Cu" "In6.Cu"
			"In7.Cu" "In8.Cu" "In9.Cu" "In10.Cu" "In11.Cu" "In12.Cu" "In13.Cu" "In14.Cu"
			"In15.Cu" "In16.Cu"
		)
		(hatch none 0.5)
		(connect_pads
			(clearance 0)
		)
		(min_thickness 0.25)
		(keepout
			(tracks not_allowed)
			(vias allowed)
			(pads allowed)
			(copperpour not_allowed)
			(footprints allowed)
		)
		(placement
			(enabled no)
			(sheetname "")
		)
		(fill
			(thermal_gap 0.5)
			(thermal_bridge_width 0.5)
			(island_removal_mode 0)
		)
		(polygon
			(pts
				(arc
					(start 16.401034 -109.297724)
					(mid 16.782034 -108.916724)
					(end 16.401034 -108.535724)
				)
				(arc
					(start 15.537434 -108.535724)
					(mid 15.156434 -108.916724)
					(end 15.537434 -109.297724)
				)
			)
		)
	)
	(zone
		(layers "F.Cu" "B.Cu" "In1.Cu" "In2.Cu" "In3.Cu" "In4.Cu" "In5.Cu" "In6.Cu"
			"In7.Cu" "In8.Cu" "In9.Cu" "In10.Cu" "In11.Cu" "In12.Cu" "In13.Cu" "In14.Cu"
			"In15.Cu" "In16.Cu"
		)
		(hatch none 0.5)
		(connect_pads
			(clearance 0)
		)
		(min_thickness 0.25)
		(keepout
			(tracks not_allowed)
			(vias allowed)
			(pads allowed)
			(copperpour not_allowed)
			(footprints allowed)
		)
		(placement
			(enabled no)
			(sheetname "")
		)
		(fill
			(thermal_gap 0.5)
			(thermal_bridge_width 0.5)
			(island_removal_mode 0)
		)
		(polygon
			(pts
				(arc
					(start 350.151192 -279.150318)
					(mid 349.493332 -279.150318)
					(end 350.151192 -279.150318)
				)
			)
		)
	)
	(zone
		(layers "F.Cu" "B.Cu" "In1.Cu" "In2.Cu" "In3.Cu" "In4.Cu" "In5.Cu" "In6.Cu"
			"In7.Cu" "In8.Cu" "In9.Cu" "In10.Cu" "In11.Cu" "In12.Cu" "In13.Cu" "In14.Cu"
			"In15.Cu" "In16.Cu"
		)
		(hatch none 0.5)
		(connect_pads
			(clearance 0)
		)
		(min_thickness 0.25)
		(keepout
			(tracks not_allowed)
			(vias allowed)
			(pads allowed)
			(copperpour not_allowed)
			(footprints allowed)
		)
		(placement
			(enabled no)
			(sheetname "")
		)
		(fill
			(thermal_gap 0.5)
			(thermal_bridge_width 0.5)
			(island_removal_mode 0)
		)
		(polygon
			(pts
				(xy 471.600022 -49.23663) (xy 471.600022 -54.23662) (xy 471.295222 -53.93182) (xy 471.295222 -49.54143)
			)
		)
	)
	(zone
		(layers "F.Cu" "B.Cu" "In1.Cu" "In2.Cu" "In3.Cu" "In4.Cu" "In5.Cu" "In6.Cu"
			"In7.Cu" "In8.Cu" "In9.Cu" "In10.Cu" "In11.Cu" "In12.Cu" "In13.Cu" "In14.Cu"
			"In15.Cu" "In16.Cu"
		)
		(hatch none 0.5)
		(connect_pads
			(clearance 0)
		)
		(min_thickness 0.25)
		(keepout
			(tracks not_allowed)
			(vias allowed)
			(pads allowed)
			(copperpour not_allowed)
			(footprints allowed)
		)
		(placement
			(enabled no)
			(sheetname "")
		)
		(fill
			(thermal_gap 0.5)
			(thermal_bridge_width 0.5)
			(island_removal_mode 0)
		)
		(polygon
			(pts
				(arc
					(start 395.328902 -4.57073)
					(mid 394.947902 -4.95173)
					(end 395.328902 -5.33273)
				)
				(arc
					(start 396.192502 -5.33273)
					(mid 396.573502 -4.95173)
					(end 396.192502 -4.57073)
				)
			)
		)
	)
	(zone
		(layers "F.Cu" "B.Cu" "In1.Cu" "In2.Cu" "In3.Cu" "In4.Cu" "In5.Cu" "In6.Cu"
			"In7.Cu" "In8.Cu" "In9.Cu" "In10.Cu" "In11.Cu" "In12.Cu" "In13.Cu" "In14.Cu"
			"In15.Cu" "In16.Cu"
		)
		(hatch none 0.5)
		(connect_pads
			(clearance 0)
		)
		(min_thickness 0.25)
		(keepout
			(tracks not_allowed)
			(vias allowed)
			(pads allowed)
			(copperpour not_allowed)
			(footprints allowed)
		)
		(placement
			(enabled no)
			(sheetname "")
		)
		(fill
			(thermal_gap 0.5)
			(thermal_bridge_width 0.5)
			(island_removal_mode 0)
		)
		(polygon
			(pts
				(arc
					(start 348.741746 -281.59202)
					(mid 348.083886 -281.59202)
					(end 348.741746 -281.59202)
				)
			)
		)
	)
	(zone
		(layers "F.Cu" "B.Cu" "In1.Cu" "In2.Cu" "In3.Cu" "In4.Cu" "In5.Cu" "In6.Cu"
			"In7.Cu" "In8.Cu" "In9.Cu" "In10.Cu" "In11.Cu" "In12.Cu" "In13.Cu" "In14.Cu"
			"In15.Cu" "In16.Cu"
		)
		(hatch none 0.5)
		(connect_pads
			(clearance 0)
		)
		(min_thickness 0.25)
		(keepout
			(tracks not_allowed)
			(vias allowed)
			(pads allowed)
			(copperpour not_allowed)
			(footprints allowed)
		)
		(placement
			(enabled no)
			(sheetname "")
		)
		(fill
			(thermal_gap 0.5)
			(thermal_bridge_width 0.5)
			(island_removal_mode 0)
		)
		(polygon
			(pts
				(arc
					(start 91.763342 -218.692222)
					(mid 91.105482 -218.692222)
					(end 91.763342 -218.692222)
				)
			)
		)
	)
	(zone
		(layers "F.Cu" "B.Cu" "In1.Cu" "In2.Cu" "In3.Cu" "In4.Cu" "In5.Cu" "In6.Cu"
			"In7.Cu" "In8.Cu" "In9.Cu" "In10.Cu" "In11.Cu" "In12.Cu" "In13.Cu" "In14.Cu"
			"In15.Cu" "In16.Cu"
		)
		(hatch none 0.5)
		(connect_pads
			(clearance 0)
		)
		(min_thickness 0.25)
		(keepout
			(tracks not_allowed)
			(vias allowed)
			(pads allowed)
			(copperpour not_allowed)
			(footprints allowed)
		)
		(placement
			(enabled no)
			(sheetname "")
		)
		(fill
			(thermal_gap 0.5)
			(thermal_bridge_width 0.5)
			(island_removal_mode 0)
		)
		(polygon
			(pts
				(arc
					(start 352.970592 -275.8948)
					(mid 352.312732 -275.8948)
					(end 352.970592 -275.8948)
				)
			)
		)
	)
	(zone
		(layers "F.Cu" "B.Cu" "In1.Cu" "In2.Cu" "In3.Cu" "In4.Cu" "In5.Cu" "In6.Cu"
			"In7.Cu" "In8.Cu" "In9.Cu" "In10.Cu" "In11.Cu" "In12.Cu" "In13.Cu" "In14.Cu"
			"In15.Cu" "In16.Cu"
		)
		(hatch none 0.5)
		(connect_pads
			(clearance 0)
		)
		(min_thickness 0.25)
		(keepout
			(tracks not_allowed)
			(vias allowed)
			(pads allowed)
			(copperpour not_allowed)
			(footprints allowed)
		)
		(placement
			(enabled no)
			(sheetname "")
		)
		(fill
			(thermal_gap 0.5)
			(thermal_bridge_width 0.5)
			(island_removal_mode 0)
		)
		(polygon
			(pts
				(arc
					(start 118.388892 -214.720932)
					(mid 118.408576 -214.673522)
					(end 118.415308 -214.622634)
				)
				(arc
					(start 118.415308 -214.622634)
					(mid 118.357652 -214.48344)
					(end 118.218458 -214.425784)
				)
				(arc
					(start 118.218458 -214.425784)
					(mid 118.120027 -214.4522)
					(end 118.048024 -214.524336)
				)
				(arc
					(start 117.578378 -215.338406)
					(mid 117.558694 -215.385816)
					(end 117.551962 -215.436704)
				)
				(arc
					(start 117.551962 -215.436704)
					(mid 117.609618 -215.575898)
					(end 117.748812 -215.633554)
				)
				(arc
					(start 117.748812 -215.633554)
					(mid 117.847243 -215.607138)
					(end 117.919246 -215.535002)
				)
			)
		)
	)
	(zone
		(layers "F.Cu" "B.Cu" "In1.Cu" "In2.Cu" "In3.Cu" "In4.Cu" "In5.Cu" "In6.Cu"
			"In7.Cu" "In8.Cu" "In9.Cu" "In10.Cu" "In11.Cu" "In12.Cu" "In13.Cu" "In14.Cu"
			"In15.Cu" "In16.Cu"
		)
		(hatch none 0.5)
		(connect_pads
			(clearance 0)
		)
		(min_thickness 0.25)
		(keepout
			(tracks not_allowed)
			(vias allowed)
			(pads allowed)
			(copperpour not_allowed)
			(footprints allowed)
		)
		(placement
			(enabled no)
			(sheetname "")
		)
		(fill
			(thermal_gap 0.5)
			(thermal_bridge_width 0.5)
			(island_removal_mode 0)
		)
		(polygon
			(pts
				(arc
					(start 359.909364 -224.389442)
					(mid 359.251504 -224.389442)
					(end 359.909364 -224.389442)
				)
			)
		)
	)
	(zone
		(layers "F.Cu" "B.Cu" "In1.Cu" "In2.Cu" "In3.Cu" "In4.Cu" "In5.Cu" "In6.Cu"
			"In7.Cu" "In8.Cu" "In9.Cu" "In10.Cu" "In11.Cu" "In12.Cu" "In13.Cu" "In14.Cu"
			"In15.Cu" "In16.Cu"
		)
		(hatch none 0.5)
		(connect_pads
			(clearance 0)
		)
		(min_thickness 0.25)
		(keepout
			(tracks not_allowed)
			(vias allowed)
			(pads allowed)
			(copperpour not_allowed)
			(footprints allowed)
		)
		(placement
			(enabled no)
			(sheetname "")
		)
		(fill
			(thermal_gap 0.5)
			(thermal_bridge_width 0.5)
			(island_removal_mode 0)
		)
		(polygon
			(pts
				(arc
					(start 63.296038 -400.477228)
					(mid 62.915038 -400.858228)
					(end 63.296038 -401.239228)
				)
				(arc
					(start 64.159638 -401.239228)
					(mid 64.540638 -400.858228)
					(end 64.159638 -400.477228)
				)
			)
		)
	)
	(zone
		(layers "F.Cu" "B.Cu" "In1.Cu" "In2.Cu" "In3.Cu" "In4.Cu" "In5.Cu" "In6.Cu"
			"In7.Cu" "In8.Cu" "In9.Cu" "In10.Cu" "In11.Cu" "In12.Cu" "In13.Cu" "In14.Cu"
			"In15.Cu" "In16.Cu"
		)
		(hatch none 0.5)
		(connect_pads
			(clearance 0)
		)
		(min_thickness 0.25)
		(keepout
			(tracks not_allowed)
			(vias allowed)
			(pads allowed)
			(copperpour not_allowed)
			(footprints allowed)
		)
		(placement
			(enabled no)
			(sheetname "")
		)
		(fill
			(thermal_gap 0.5)
			(thermal_bridge_width 0.5)
			(island_removal_mode 0)
		)
		(polygon
			(pts
				(arc
					(start 101.553264 -285.661354)
					(mid 102.211124 -285.661354)
					(end 101.553264 -285.661354)
				)
			)
		)
	)
	(zone
		(layers "F.Cu" "B.Cu" "In1.Cu" "In2.Cu" "In3.Cu" "In4.Cu" "In5.Cu" "In6.Cu"
			"In7.Cu" "In8.Cu" "In9.Cu" "In10.Cu" "In11.Cu" "In12.Cu" "In13.Cu" "In14.Cu"
			"In15.Cu" "In16.Cu"
		)
		(hatch none 0.5)
		(connect_pads
			(clearance 0)
		)
		(min_thickness 0.25)
		(keepout
			(tracks not_allowed)
			(vias allowed)
			(pads allowed)
			(copperpour not_allowed)
			(footprints allowed)
		)
		(placement
			(enabled no)
			(sheetname "")
		)
		(fill
			(thermal_gap 0.5)
			(thermal_bridge_width 0.5)
			(island_removal_mode 0)
		)
		(polygon
			(pts
				(arc
					(start 64.642238 -406.62352)
					(mid 64.261238 -407.00452)
					(end 64.642238 -407.38552)
				)
				(arc
					(start 65.505838 -407.38552)
					(mid 65.886838 -407.00452)
					(end 65.505838 -406.62352)
				)
			)
		)
	)
	(zone
		(layers "F.Cu" "B.Cu" "In1.Cu" "In2.Cu" "In3.Cu" "In4.Cu" "In5.Cu" "In6.Cu"
			"In7.Cu" "In8.Cu" "In9.Cu" "In10.Cu" "In11.Cu" "In12.Cu" "In13.Cu" "In14.Cu"
			"In15.Cu" "In16.Cu"
		)
		(hatch none 0.5)
		(connect_pads
			(clearance 0)
		)
		(min_thickness 0.25)
		(keepout
			(tracks not_allowed)
			(vias allowed)
			(pads allowed)
			(copperpour not_allowed)
			(footprints allowed)
		)
		(placement
			(enabled no)
			(sheetname "")
		)
		(fill
			(thermal_gap 0.5)
			(thermal_bridge_width 0.5)
			(island_removal_mode 0)
		)
		(polygon
			(pts
				(arc
					(start 370.668296 -285.759652)
					(mid 370.68798 -285.712242)
					(end 370.694712 -285.661354)
				)
				(arc
					(start 370.694712 -285.661354)
					(mid 370.637056 -285.52216)
					(end 370.497862 -285.464504)
				)
				(arc
					(start 370.497862 -285.464504)
					(mid 370.399431 -285.49092)
					(end 370.327428 -285.563056)
				)
				(arc
					(start 369.857782 -286.377126)
					(mid 369.838098 -286.424536)
					(end 369.831366 -286.475424)
				)
				(arc
					(start 369.831366 -286.475424)
					(mid 369.889022 -286.614618)
					(end 370.028216 -286.672274)
				)
				(arc
					(start 370.028216 -286.672274)
					(mid 370.126647 -286.645858)
					(end 370.19865 -286.573722)
				)
			)
		)
	)
	(zone
		(layers "F.Cu" "B.Cu" "In1.Cu" "In2.Cu" "In3.Cu" "In4.Cu" "In5.Cu" "In6.Cu"
			"In7.Cu" "In8.Cu" "In9.Cu" "In10.Cu" "In11.Cu" "In12.Cu" "In13.Cu" "In14.Cu"
			"In15.Cu" "In16.Cu"
		)
		(hatch none 0.5)
		(connect_pads
			(clearance 0)
		)
		(min_thickness 0.25)
		(keepout
			(tracks not_allowed)
			(vias allowed)
			(pads allowed)
			(copperpour not_allowed)
			(footprints allowed)
		)
		(placement
			(enabled no)
			(sheetname "")
		)
		(fill
			(thermal_gap 0.5)
			(thermal_bridge_width 0.5)
			(island_removal_mode 0)
		)
		(polygon
			(pts
				(arc
					(start 376.825764 -221.133924)
					(mid 376.167904 -221.133924)
					(end 376.825764 -221.133924)
				)
			)
		)
	)
	(zone
		(layers "F.Cu" "B.Cu" "In1.Cu" "In2.Cu" "In3.Cu" "In4.Cu" "In5.Cu" "In6.Cu"
			"In7.Cu" "In8.Cu" "In9.Cu" "In10.Cu" "In11.Cu" "In12.Cu" "In13.Cu" "In14.Cu"
			"In15.Cu" "In16.Cu"
		)
		(hatch none 0.5)
		(connect_pads
			(clearance 0)
		)
		(min_thickness 0.25)
		(keepout
			(tracks not_allowed)
			(vias allowed)
			(pads allowed)
			(copperpour not_allowed)
			(footprints allowed)
		)
		(placement
			(enabled no)
			(sheetname "")
		)
		(fill
			(thermal_gap 0.5)
			(thermal_bridge_width 0.5)
			(island_removal_mode 0)
		)
		(polygon
			(pts
				(arc
					(start 43.779694 -17.23136)
					(mid 43.398694 -17.61236)
					(end 43.779694 -17.99336)
				)
				(arc
					(start 44.643294 -17.99336)
					(mid 45.024294 -17.61236)
					(end 44.643294 -17.23136)
				)
			)
		)
	)
	(zone
		(layers "F.Cu" "B.Cu" "In1.Cu" "In2.Cu" "In3.Cu" "In4.Cu" "In5.Cu" "In6.Cu"
			"In7.Cu" "In8.Cu" "In9.Cu" "In10.Cu" "In11.Cu" "In12.Cu" "In13.Cu" "In14.Cu"
			"In15.Cu" "In16.Cu"
		)
		(hatch none 0.5)
		(connect_pads
			(clearance 0)
		)
		(min_thickness 0.25)
		(keepout
			(tracks not_allowed)
			(vias allowed)
			(pads allowed)
			(copperpour not_allowed)
			(footprints allowed)
		)
		(placement
			(enabled no)
			(sheetname "")
		)
		(fill
			(thermal_gap 0.5)
			(thermal_bridge_width 0.5)
			(island_removal_mode 0)
		)
		(polygon
			(pts
				(arc
					(start 370.247164 -217.878406)
					(mid 369.589304 -217.878406)
					(end 370.247164 -217.878406)
				)
			)
		)
	)
	(zone
		(layers "F.Cu" "B.Cu" "In1.Cu" "In2.Cu" "In3.Cu" "In4.Cu" "In5.Cu" "In6.Cu"
			"In7.Cu" "In8.Cu" "In9.Cu" "In10.Cu" "In11.Cu" "In12.Cu" "In13.Cu" "In14.Cu"
			"In15.Cu" "In16.Cu"
		)
		(hatch none 0.5)
		(connect_pads
			(clearance 0)
		)
		(min_thickness 0.25)
		(keepout
			(tracks not_allowed)
			(vias allowed)
			(pads allowed)
			(copperpour not_allowed)
			(footprints allowed)
		)
		(placement
			(enabled no)
			(sheetname "")
		)
		(fill
			(thermal_gap 0.5)
			(thermal_bridge_width 0.5)
			(island_removal_mode 0)
		)
		(polygon
			(pts
				(arc
					(start 377.54941 -403.502876)
					(mid 377.16841 -403.883876)
					(end 377.54941 -404.264876)
				)
				(arc
					(start 378.41301 -404.264876)
					(mid 378.79401 -403.883876)
					(end 378.41301 -403.502876)
				)
			)
		)
	)
	(zone
		(layers "F.Cu" "B.Cu" "In1.Cu" "In2.Cu" "In3.Cu" "In4.Cu" "In5.Cu" "In6.Cu"
			"In7.Cu" "In8.Cu" "In9.Cu" "In10.Cu" "In11.Cu" "In12.Cu" "In13.Cu" "In14.Cu"
			"In15.Cu" "In16.Cu"
		)
		(hatch none 0.5)
		(connect_pads
			(clearance 0)
		)
		(min_thickness 0.25)
		(keepout
			(tracks not_allowed)
			(vias allowed)
			(pads allowed)
			(copperpour not_allowed)
			(footprints allowed)
		)
		(placement
			(enabled no)
			(sheetname "")
		)
		(fill
			(thermal_gap 0.5)
			(thermal_bridge_width 0.5)
			(island_removal_mode 0)
		)
		(polygon
			(pts
				(arc
					(start 349.571564 -224.389442)
					(mid 348.913704 -224.389442)
					(end 349.571564 -224.389442)
				)
			)
		)
	)
	(zone
		(layers "F.Cu" "B.Cu" "In1.Cu" "In2.Cu" "In3.Cu" "In4.Cu" "In5.Cu" "In6.Cu"
			"In7.Cu" "In8.Cu" "In9.Cu" "In10.Cu" "In11.Cu" "In12.Cu" "In13.Cu" "In14.Cu"
			"In15.Cu" "In16.Cu"
		)
		(hatch none 0.5)
		(connect_pads
			(clearance 0)
		)
		(min_thickness 0.25)
		(keepout
			(tracks not_allowed)
			(vias allowed)
			(pads allowed)
			(copperpour not_allowed)
			(footprints allowed)
		)
		(placement
			(enabled no)
			(sheetname "")
		)
		(fill
			(thermal_gap 0.5)
			(thermal_bridge_width 0.5)
			(island_removal_mode 0)
		)
		(polygon
			(pts
				(arc
					(start 357.55961 -215.436704)
					(mid 356.90175 -215.436704)
					(end 357.55961 -215.436704)
				)
			)
		)
	)
	(zone
		(layers "F.Cu" "B.Cu" "In1.Cu" "In2.Cu" "In3.Cu" "In4.Cu" "In5.Cu" "In6.Cu"
			"In7.Cu" "In8.Cu" "In9.Cu" "In10.Cu" "In11.Cu" "In12.Cu" "In13.Cu" "In14.Cu"
			"In15.Cu" "In16.Cu"
		)
		(hatch none 0.5)
		(connect_pads
			(clearance 0)
		)
		(min_thickness 0.25)
		(keepout
			(tracks not_allowed)
			(vias allowed)
			(pads allowed)
			(copperpour not_allowed)
			(footprints allowed)
		)
		(placement
			(enabled no)
			(sheetname "")
		)
		(fill
			(thermal_gap 0.5)
			(thermal_bridge_width 0.5)
			(island_removal_mode 0)
		)
		(polygon
			(pts
				(arc
					(start 126.37008 -213.646766)
					(mid 126.302372 -213.574915)
					(end 126.207266 -213.548468)
				)
				(arc
					(start 126.207266 -213.548468)
					(mid 126.077052 -213.602404)
					(end 126.023116 -213.732618)
				)
				(arc
					(start 126.023116 -213.732618)
					(mid 126.028567 -213.776839)
					(end 126.044452 -213.81847)
				)
				(arc
					(start 126.513844 -214.708486)
					(mid 126.581552 -214.780337)
					(end 126.676658 -214.806784)
				)
				(arc
					(start 126.676658 -214.806784)
					(mid 126.806872 -214.752848)
					(end 126.860808 -214.622634)
				)
				(arc
					(start 126.860808 -214.622634)
					(mid 126.855357 -214.578413)
					(end 126.839472 -214.536782)
				)
			)
		)
	)
	(zone
		(layers "F.Cu" "B.Cu" "In1.Cu" "In2.Cu" "In3.Cu" "In4.Cu" "In5.Cu" "In6.Cu"
			"In7.Cu" "In8.Cu" "In9.Cu" "In10.Cu" "In11.Cu" "In12.Cu" "In13.Cu" "In14.Cu"
			"In15.Cu" "In16.Cu"
		)
		(hatch none 0.5)
		(connect_pads
			(clearance 0)
		)
		(min_thickness 0.25)
		(keepout
			(tracks not_allowed)
			(vias allowed)
			(pads allowed)
			(copperpour not_allowed)
			(footprints allowed)
		)
		(placement
			(enabled no)
			(sheetname "")
		)
		(fill
			(thermal_gap 0.5)
			(thermal_bridge_width 0.5)
			(island_removal_mode 0)
		)
		(polygon
			(pts
				(arc
					(start 360.69016 -221.231968)
					(mid 360.709844 -221.184558)
					(end 360.716576 -221.13367)
				)
				(arc
					(start 360.716576 -221.13367)
					(mid 360.65892 -220.994476)
					(end 360.519726 -220.93682)
				)
				(arc
					(start 360.519726 -220.93682)
					(mid 360.421295 -220.963236)
					(end 360.349292 -221.035372)
				)
				(arc
					(start 359.879646 -221.849442)
					(mid 359.859962 -221.896852)
					(end 359.85323 -221.94774)
				)
				(arc
					(start 359.85323 -221.94774)
					(mid 359.910886 -222.086934)
					(end 360.05008 -222.14459)
				)
				(arc
					(start 360.05008 -222.14459)
					(mid 360.148511 -222.118174)
					(end 360.220514 -222.046038)
				)
			)
		)
	)
	(zone
		(layers "F.Cu" "B.Cu" "In1.Cu" "In2.Cu" "In3.Cu" "In4.Cu" "In5.Cu" "In6.Cu"
			"In7.Cu" "In8.Cu" "In9.Cu" "In10.Cu" "In11.Cu" "In12.Cu" "In13.Cu" "In14.Cu"
			"In15.Cu" "In16.Cu"
		)
		(hatch none 0.5)
		(connect_pads
			(clearance 0)
		)
		(min_thickness 0.25)
		(keepout
			(tracks not_allowed)
			(vias allowed)
			(pads allowed)
			(copperpour not_allowed)
			(footprints allowed)
		)
		(placement
			(enabled no)
			(sheetname "")
		)
		(fill
			(thermal_gap 0.5)
			(thermal_bridge_width 0.5)
			(island_removal_mode 0)
		)
		(polygon
			(pts
				(arc
					(start 333.282544 -72.757792)
					(mid 333.663544 -72.376792)
					(end 333.282544 -71.995792)
				)
				(arc
					(start 332.418944 -71.995792)
					(mid 332.037944 -72.376792)
					(end 332.418944 -72.757792)
				)
			)
		)
	)
	(zone
		(layers "F.Cu" "B.Cu" "In1.Cu" "In2.Cu" "In3.Cu" "In4.Cu" "In5.Cu" "In6.Cu"
			"In7.Cu" "In8.Cu" "In9.Cu" "In10.Cu" "In11.Cu" "In12.Cu" "In13.Cu" "In14.Cu"
			"In15.Cu" "In16.Cu"
		)
		(hatch none 0.5)
		(connect_pads
			(clearance 0)
		)
		(min_thickness 0.25)
		(keepout
			(tracks not_allowed)
			(vias allowed)
			(pads allowed)
			(copperpour not_allowed)
			(footprints allowed)
		)
		(placement
			(enabled no)
			(sheetname "")
		)
		(fill
			(thermal_gap 0.5)
			(thermal_bridge_width 0.5)
			(island_removal_mode 0)
		)
		(polygon
			(pts
				(arc
					(start 115.258596 -213.732618)
					(mid 114.600736 -213.732618)
					(end 115.258596 -213.732618)
				)
			)
		)
	)
	(zone
		(layers "F.Cu" "B.Cu" "In1.Cu" "In2.Cu" "In3.Cu" "In4.Cu" "In5.Cu" "In6.Cu"
			"In7.Cu" "In8.Cu" "In9.Cu" "In10.Cu" "In11.Cu" "In12.Cu" "In13.Cu" "In14.Cu"
			"In15.Cu" "In16.Cu"
		)
		(hatch none 0.5)
		(connect_pads
			(clearance 0)
		)
		(min_thickness 0.25)
		(keepout
			(tracks not_allowed)
			(vias allowed)
			(pads allowed)
			(copperpour not_allowed)
			(footprints allowed)
		)
		(placement
			(enabled no)
			(sheetname "")
		)
		(fill
			(thermal_gap 0.5)
			(thermal_bridge_width 0.5)
			(island_removal_mode 0)
		)
		(polygon
			(pts
				(arc
					(start 103.822246 -217.162634)
					(mid 103.84193 -217.115224)
					(end 103.848662 -217.064336)
				)
				(arc
					(start 103.848662 -217.064336)
					(mid 103.791006 -216.925142)
					(end 103.651812 -216.867486)
				)
				(arc
					(start 103.651812 -216.867486)
					(mid 103.553381 -216.893902)
					(end 103.481378 -216.966038)
				)
				(arc
					(start 103.011732 -217.780108)
					(mid 102.992048 -217.827518)
					(end 102.985316 -217.878406)
				)
				(arc
					(start 102.985316 -217.878406)
					(mid 103.042972 -218.0176)
					(end 103.182166 -218.075256)
				)
				(arc
					(start 103.182166 -218.075256)
					(mid 103.280597 -218.04884)
					(end 103.3526 -217.976704)
				)
			)
		)
	)
	(zone
		(layers "F.Cu" "B.Cu" "In1.Cu" "In2.Cu" "In3.Cu" "In4.Cu" "In5.Cu" "In6.Cu"
			"In7.Cu" "In8.Cu" "In9.Cu" "In10.Cu" "In11.Cu" "In12.Cu" "In13.Cu" "In14.Cu"
			"In15.Cu" "In16.Cu"
		)
		(hatch none 0.5)
		(connect_pads
			(clearance 0)
		)
		(min_thickness 0.25)
		(keepout
			(tracks not_allowed)
			(vias allowed)
			(pads allowed)
			(copperpour not_allowed)
			(footprints allowed)
		)
		(placement
			(enabled no)
			(sheetname "")
		)
		(fill
			(thermal_gap 0.5)
			(thermal_bridge_width 0.5)
			(island_removal_mode 0)
		)
		(polygon
			(pts
				(arc
					(start 353.874324 -176.709832)
					(mid 354.233534 -176.561042)
					(end 354.382324 -176.201832)
				)
				(arc
					(start 354.382324 -176.201832)
					(mid 354.314267 -175.947835)
					(end 354.128324 -175.761904)
				)
				(arc
					(start 353.204272 -175.22825)
					(mid 353.081978 -175.177713)
					(end 352.95078 -175.160432)
				)
				(arc
					(start 352.950272 -175.160432)
					(mid 352.591062 -175.309222)
					(end 352.442272 -175.668432)
				)
				(arc
					(start 352.442272 -175.668432)
					(mid 352.510329 -175.922429)
					(end 352.696272 -176.10836)
				)
				(arc
					(start 353.620324 -176.642014)
					(mid 353.742618 -176.692551)
					(end 353.873816 -176.709832)
				)
			)
		)
	)
	(zone
		(layers "F.Cu" "B.Cu" "In1.Cu" "In2.Cu" "In3.Cu" "In4.Cu" "In5.Cu" "In6.Cu"
			"In7.Cu" "In8.Cu" "In9.Cu" "In10.Cu" "In11.Cu" "In12.Cu" "In13.Cu" "In14.Cu"
			"In15.Cu" "In16.Cu"
		)
		(hatch none 0.5)
		(connect_pads
			(clearance 0)
		)
		(min_thickness 0.25)
		(keepout
			(tracks not_allowed)
			(vias allowed)
			(pads allowed)
			(copperpour not_allowed)
			(footprints allowed)
		)
		(placement
			(enabled no)
			(sheetname "")
		)
		(fill
			(thermal_gap 0.5)
			(thermal_bridge_width 0.5)
			(island_removal_mode 0)
		)
		(polygon
			(pts
				(arc
					(start 104.372664 -280.778204)
					(mid 105.030524 -280.778204)
					(end 104.372664 -280.778204)
				)
			)
		)
	)
	(zone
		(layers "F.Cu" "B.Cu" "In1.Cu" "In2.Cu" "In3.Cu" "In4.Cu" "In5.Cu" "In6.Cu"
			"In7.Cu" "In8.Cu" "In9.Cu" "In10.Cu" "In11.Cu" "In12.Cu" "In13.Cu" "In14.Cu"
			"In15.Cu" "In16.Cu"
		)
		(hatch none 0.5)
		(connect_pads
			(clearance 0)
		)
		(min_thickness 0.25)
		(keepout
			(tracks not_allowed)
			(vias allowed)
			(pads allowed)
			(copperpour not_allowed)
			(footprints allowed)
		)
		(placement
			(enabled no)
			(sheetname "")
		)
		(fill
			(thermal_gap 0.5)
			(thermal_bridge_width 0.5)
			(island_removal_mode 0)
		)
		(polygon
			(pts
				(arc
					(start 359.909364 -221.133924)
					(mid 359.251504 -221.133924)
					(end 359.909364 -221.133924)
				)
			)
		)
	)
	(zone
		(layers "F.Cu" "B.Cu" "In1.Cu" "In2.Cu" "In3.Cu" "In4.Cu" "In5.Cu" "In6.Cu"
			"In7.Cu" "In8.Cu" "In9.Cu" "In10.Cu" "In11.Cu" "In12.Cu" "In13.Cu" "In14.Cu"
			"In15.Cu" "In16.Cu"
		)
		(hatch none 0.5)
		(connect_pads
			(clearance 0)
		)
		(min_thickness 0.25)
		(keepout
			(tracks not_allowed)
			(vias allowed)
			(pads allowed)
			(copperpour not_allowed)
			(footprints allowed)
		)
		(placement
			(enabled no)
			(sheetname "")
		)
		(fill
			(thermal_gap 0.5)
			(thermal_bridge_width 0.5)
			(island_removal_mode 0)
		)
		(polygon
			(pts
				(arc
					(start 345.812364 -224.389442)
					(mid 345.154504 -224.389442)
					(end 345.812364 -224.389442)
				)
			)
		)
	)
	(zone
		(layers "F.Cu" "B.Cu" "In1.Cu" "In2.Cu" "In3.Cu" "In4.Cu" "In5.Cu" "In6.Cu"
			"In7.Cu" "In8.Cu" "In9.Cu" "In10.Cu" "In11.Cu" "In12.Cu" "In13.Cu" "In14.Cu"
			"In15.Cu" "In16.Cu"
		)
		(hatch none 0.5)
		(connect_pads
			(clearance 0)
		)
		(min_thickness 0.25)
		(keepout
			(tracks not_allowed)
			(vias allowed)
			(pads allowed)
			(copperpour not_allowed)
			(footprints allowed)
		)
		(placement
			(enabled no)
			(sheetname "")
		)
		(fill
			(thermal_gap 0.5)
			(thermal_bridge_width 0.5)
			(island_removal_mode 0)
		)
		(polygon
			(pts
				(arc
					(start 130.717036 -288.005012)
					(mid 130.645047 -287.932853)
					(end 130.546602 -287.90646)
				)
				(arc
					(start 130.546602 -287.90646)
					(mid 130.407408 -287.964116)
					(end 130.349752 -288.10331)
				)
				(arc
					(start 130.349752 -288.10331)
					(mid 130.356509 -288.154191)
					(end 130.376168 -288.201608)
				)
				(arc
					(start 130.845814 -289.015424)
					(mid 130.917803 -289.087583)
					(end 131.016248 -289.113976)
				)
				(arc
					(start 131.016248 -289.113976)
					(mid 131.155442 -289.05632)
					(end 131.213098 -288.917126)
				)
				(arc
					(start 131.213098 -288.917126)
					(mid 131.206341 -288.866245)
					(end 131.186682 -288.818828)
				)
			)
		)
	)
	(zone
		(layers "F.Cu" "B.Cu" "In1.Cu" "In2.Cu" "In3.Cu" "In4.Cu" "In5.Cu" "In6.Cu"
			"In7.Cu" "In8.Cu" "In9.Cu" "In10.Cu" "In11.Cu" "In12.Cu" "In13.Cu" "In14.Cu"
			"In15.Cu" "In16.Cu"
		)
		(hatch none 0.5)
		(connect_pads
			(clearance 0)
		)
		(min_thickness 0.25)
		(keepout
			(tracks not_allowed)
			(vias allowed)
			(pads allowed)
			(copperpour not_allowed)
			(footprints allowed)
		)
		(placement
			(enabled no)
			(sheetname "")
		)
		(fill
			(thermal_gap 0.5)
			(thermal_bridge_width 0.5)
			(island_removal_mode 0)
		)
		(polygon
			(pts
				(arc
					(start 58.20029 -7.105396)
					(mid 58.58129 -6.724396)
					(end 58.20029 -6.343396)
				)
				(arc
					(start 57.33669 -6.343396)
					(mid 56.95569 -6.724396)
					(end 57.33669 -7.105396)
				)
			)
		)
	)
	(zone
		(layers "F.Cu" "B.Cu" "In1.Cu" "In2.Cu" "In3.Cu" "In4.Cu" "In5.Cu" "In6.Cu"
			"In7.Cu" "In8.Cu" "In9.Cu" "In10.Cu" "In11.Cu" "In12.Cu" "In13.Cu" "In14.Cu"
			"In15.Cu" "In16.Cu"
		)
		(hatch none 0.5)
		(connect_pads
			(clearance 0)
		)
		(min_thickness 0.25)
		(keepout
			(tracks not_allowed)
			(vias allowed)
			(pads allowed)
			(copperpour not_allowed)
			(footprints allowed)
		)
		(placement
			(enabled no)
			(sheetname "")
		)
		(fill
			(thermal_gap 0.5)
			(thermal_bridge_width 0.5)
			(island_removal_mode 0)
		)
		(polygon
			(pts
				(arc
					(start 339.70341 -218.692222)
					(mid 339.04555 -218.692222)
					(end 339.70341 -218.692222)
				)
			)
		)
	)
	(zone
		(layers "F.Cu" "B.Cu" "In1.Cu" "In2.Cu" "In3.Cu" "In4.Cu" "In5.Cu" "In6.Cu"
			"In7.Cu" "In8.Cu" "In9.Cu" "In10.Cu" "In11.Cu" "In12.Cu" "In13.Cu" "In14.Cu"
			"In15.Cu" "In16.Cu"
		)
		(hatch none 0.5)
		(connect_pads
			(clearance 0)
		)
		(min_thickness 0.25)
		(keepout
			(tracks not_allowed)
			(vias allowed)
			(pads allowed)
			(copperpour not_allowed)
			(footprints allowed)
		)
		(placement
			(enabled no)
			(sheetname "")
		)
		(fill
			(thermal_gap 0.5)
			(thermal_bridge_width 0.5)
			(island_removal_mode 0)
		)
		(polygon
			(pts
				(arc
					(start 55.541418 -4.581652)
					(mid 55.160418 -4.962652)
					(end 55.541418 -5.343652)
				)
				(arc
					(start 56.405018 -5.343652)
					(mid 56.786018 -4.962652)
					(end 56.405018 -4.581652)
				)
			)
		)
	)
	(zone
		(layers "F.Cu" "B.Cu" "In1.Cu" "In2.Cu" "In3.Cu" "In4.Cu" "In5.Cu" "In6.Cu"
			"In7.Cu" "In8.Cu" "In9.Cu" "In10.Cu" "In11.Cu" "In12.Cu" "In13.Cu" "In14.Cu"
			"In15.Cu" "In16.Cu"
		)
		(hatch none 0.5)
		(connect_pads
			(clearance 0)
		)
		(min_thickness 0.25)
		(keepout
			(tracks not_allowed)
			(vias allowed)
			(pads allowed)
			(copperpour not_allowed)
			(footprints allowed)
		)
		(placement
			(enabled no)
			(sheetname "")
		)
		(fill
			(thermal_gap 0.5)
			(thermal_bridge_width 0.5)
			(island_removal_mode 0)
		)
		(polygon
			(pts
				(arc
					(start 376.29973 -289.003232)
					(mid 376.315654 -288.961481)
					(end 376.321066 -288.917126)
				)
				(arc
					(start 376.321066 -288.917126)
					(mid 376.26713 -288.786912)
					(end 376.136916 -288.732976)
				)
				(arc
					(start 376.136916 -288.732976)
					(mid 376.041896 -288.759384)
					(end 375.974102 -288.83102)
				)
				(arc
					(start 375.503948 -289.721036)
					(mid 375.488024 -289.762787)
					(end 375.482612 -289.807142)
				)
				(arc
					(start 375.482612 -289.807142)
					(mid 375.536548 -289.937356)
					(end 375.666762 -289.991292)
				)
				(arc
					(start 375.666762 -289.991292)
					(mid 375.761782 -289.964884)
					(end 375.829576 -289.893248)
				)
			)
		)
	)
	(zone
		(layers "F.Cu" "B.Cu" "In1.Cu" "In2.Cu" "In3.Cu" "In4.Cu" "In5.Cu" "In6.Cu"
			"In7.Cu" "In8.Cu" "In9.Cu" "In10.Cu" "In11.Cu" "In12.Cu" "In13.Cu" "In14.Cu"
			"In15.Cu" "In16.Cu"
		)
		(hatch none 0.5)
		(connect_pads
			(clearance 0)
		)
		(min_thickness 0.25)
		(keepout
			(tracks not_allowed)
			(vias allowed)
			(pads allowed)
			(copperpour not_allowed)
			(footprints allowed)
		)
		(placement
			(enabled no)
			(sheetname "")
		)
		(fill
			(thermal_gap 0.5)
			(thermal_bridge_width 0.5)
			(island_removal_mode 0)
		)
		(polygon
			(pts
				(arc
					(start 445.839088 -6.332474)
					(mid 445.458088 -6.713474)
					(end 445.839088 -7.094474)
				)
				(arc
					(start 446.702688 -7.094474)
					(mid 447.083688 -6.713474)
					(end 446.702688 -6.332474)
				)
			)
		)
	)
	(zone
		(layers "F.Cu" "B.Cu" "In1.Cu" "In2.Cu" "In3.Cu" "In4.Cu" "In5.Cu" "In6.Cu"
			"In7.Cu" "In8.Cu" "In9.Cu" "In10.Cu" "In11.Cu" "In12.Cu" "In13.Cu" "In14.Cu"
			"In15.Cu" "In16.Cu"
		)
		(hatch none 0.5)
		(connect_pads
			(clearance 0)
		)
		(min_thickness 0.25)
		(keepout
			(tracks not_allowed)
			(vias allowed)
			(pads allowed)
			(copperpour not_allowed)
			(footprints allowed)
		)
		(placement
			(enabled no)
			(sheetname "")
		)
		(fill
			(thermal_gap 0.5)
			(thermal_bridge_width 0.5)
			(island_removal_mode 0)
		)
		(polygon
			(pts
				(arc
					(start 115.728496 -217.878406)
					(mid 115.070636 -217.878406)
					(end 115.728496 -217.878406)
				)
			)
		)
	)
	(zone
		(layers "F.Cu" "B.Cu" "In1.Cu" "In2.Cu" "In3.Cu" "In4.Cu" "In5.Cu" "In6.Cu"
			"In7.Cu" "In8.Cu" "In9.Cu" "In10.Cu" "In11.Cu" "In12.Cu" "In13.Cu" "In14.Cu"
			"In15.Cu" "In16.Cu"
		)
		(hatch none 0.5)
		(connect_pads
			(clearance 0)
		)
		(min_thickness 0.25)
		(keepout
			(tracks not_allowed)
			(vias allowed)
			(pads allowed)
			(copperpour not_allowed)
			(footprints allowed)
		)
		(placement
			(enabled no)
			(sheetname "")
		)
		(fill
			(thermal_gap 0.5)
			(thermal_bridge_width 0.5)
			(island_removal_mode 0)
		)
		(polygon
			(pts
				(arc
					(start 100.691696 -221.133924)
					(mid 100.033836 -221.133924)
					(end 100.691696 -221.133924)
				)
			)
		)
	)
	(zone
		(layers "F.Cu" "B.Cu" "In1.Cu" "In2.Cu" "In3.Cu" "In4.Cu" "In5.Cu" "In6.Cu"
			"In7.Cu" "In8.Cu" "In9.Cu" "In10.Cu" "In11.Cu" "In12.Cu" "In13.Cu" "In14.Cu"
			"In15.Cu" "In16.Cu"
		)
		(hatch none 0.5)
		(connect_pads
			(clearance 0)
		)
		(min_thickness 0.25)
		(keepout
			(tracks not_allowed)
			(vias allowed)
			(pads allowed)
			(copperpour not_allowed)
			(footprints allowed)
		)
		(placement
			(enabled no)
			(sheetname "")
		)
		(fill
			(thermal_gap 0.5)
			(thermal_bridge_width 0.5)
			(island_removal_mode 0)
		)
		(polygon
			(pts
				(arc
					(start 368.78133 -289.003232)
					(mid 368.797254 -288.961481)
					(end 368.802666 -288.917126)
				)
				(arc
					(start 368.802666 -288.917126)
					(mid 368.74873 -288.786912)
					(end 368.618516 -288.732976)
				)
				(arc
					(start 368.618516 -288.732976)
					(mid 368.523496 -288.759384)
					(end 368.455702 -288.83102)
				)
				(arc
					(start 367.985548 -289.721036)
					(mid 367.969624 -289.762787)
					(end 367.964212 -289.807142)
				)
				(arc
					(start 367.964212 -289.807142)
					(mid 368.018148 -289.937356)
					(end 368.148362 -289.991292)
				)
				(arc
					(start 368.148362 -289.991292)
					(mid 368.243382 -289.964884)
					(end 368.311176 -289.893248)
				)
			)
		)
	)
	(zone
		(layers "F.Cu" "B.Cu" "In1.Cu" "In2.Cu" "In3.Cu" "In4.Cu" "In5.Cu" "In6.Cu"
			"In7.Cu" "In8.Cu" "In9.Cu" "In10.Cu" "In11.Cu" "In12.Cu" "In13.Cu" "In14.Cu"
			"In15.Cu" "In16.Cu"
		)
		(hatch none 0.5)
		(connect_pads
			(clearance 0)
		)
		(min_thickness 0.25)
		(keepout
			(tracks not_allowed)
			(vias allowed)
			(pads allowed)
			(copperpour not_allowed)
			(footprints allowed)
		)
		(placement
			(enabled no)
			(sheetname "")
		)
		(fill
			(thermal_gap 0.5)
			(thermal_bridge_width 0.5)
			(island_removal_mode 0)
		)
		(polygon
			(pts
				(arc
					(start 131.234942 -218.692222)
					(mid 130.577082 -218.692222)
					(end 131.234942 -218.692222)
				)
			)
		)
	)
	(zone
		(layers "F.Cu" "B.Cu" "In1.Cu" "In2.Cu" "In3.Cu" "In4.Cu" "In5.Cu" "In6.Cu"
			"In7.Cu" "In8.Cu" "In9.Cu" "In10.Cu" "In11.Cu" "In12.Cu" "In13.Cu" "In14.Cu"
			"In15.Cu" "In16.Cu"
		)
		(hatch none 0.5)
		(connect_pads
			(clearance 0)
		)
		(min_thickness 0.25)
		(keepout
			(tracks not_allowed)
			(vias allowed)
			(pads allowed)
			(copperpour not_allowed)
			(footprints allowed)
		)
		(placement
			(enabled no)
			(sheetname "")
		)
		(fill
			(thermal_gap 0.5)
			(thermal_bridge_width 0.5)
			(island_removal_mode 0)
		)
		(polygon
			(pts
				(arc
					(start 106.252264 -282.405836)
					(mid 106.910124 -282.405836)
					(end 106.252264 -282.405836)
				)
			)
		)
	)
	(zone
		(layers "F.Cu" "B.Cu" "In1.Cu" "In2.Cu" "In3.Cu" "In4.Cu" "In5.Cu" "In6.Cu"
			"In7.Cu" "In8.Cu" "In9.Cu" "In10.Cu" "In11.Cu" "In12.Cu" "In13.Cu" "In14.Cu"
			"In15.Cu" "In16.Cu"
		)
		(hatch none 0.5)
		(connect_pads
			(clearance 0)
		)
		(min_thickness 0.25)
		(keepout
			(tracks not_allowed)
			(vias allowed)
			(pads allowed)
			(copperpour not_allowed)
			(footprints allowed)
		)
		(placement
			(enabled no)
			(sheetname "")
		)
		(fill
			(thermal_gap 0.5)
			(thermal_bridge_width 0.5)
			(island_removal_mode 0)
		)
		(polygon
			(pts
				(arc
					(start 350.511364 -221.133924)
					(mid 349.853504 -221.133924)
					(end 350.511364 -221.133924)
				)
			)
		)
	)
	(zone
		(layers "F.Cu" "B.Cu" "In1.Cu" "In2.Cu" "In3.Cu" "In4.Cu" "In5.Cu" "In6.Cu"
			"In7.Cu" "In8.Cu" "In9.Cu" "In10.Cu" "In11.Cu" "In12.Cu" "In13.Cu" "In14.Cu"
			"In15.Cu" "In16.Cu"
		)
		(hatch none 0.5)
		(connect_pads
			(clearance 0)
		)
		(min_thickness 0.25)
		(keepout
			(tracks not_allowed)
			(vias allowed)
			(pads allowed)
			(copperpour not_allowed)
			(footprints allowed)
		)
		(placement
			(enabled no)
			(sheetname "")
		)
		(fill
			(thermal_gap 0.5)
			(thermal_bridge_width 0.5)
			(island_removal_mode 0)
		)
		(polygon
			(pts
				(arc
					(start 127.757682 -220.319854)
					(mid 128.415542 -220.319854)
					(end 127.757682 -220.319854)
				)
			)
		)
	)
	(zone
		(layers "F.Cu" "B.Cu" "In1.Cu" "In2.Cu" "In3.Cu" "In4.Cu" "In5.Cu" "In6.Cu"
			"In7.Cu" "In8.Cu" "In9.Cu" "In10.Cu" "In11.Cu" "In12.Cu" "In13.Cu" "In14.Cu"
			"In15.Cu" "In16.Cu"
		)
		(hatch none 0.5)
		(connect_pads
			(clearance 0)
		)
		(min_thickness 0.25)
		(keepout
			(tracks not_allowed)
			(vias allowed)
			(pads allowed)
			(copperpour not_allowed)
			(footprints allowed)
		)
		(placement
			(enabled no)
			(sheetname "")
		)
		(fill
			(thermal_gap 0.5)
			(thermal_bridge_width 0.5)
			(island_removal_mode 0)
		)
		(polygon
			(pts
				(arc
					(start 340.283292 -281.59202)
					(mid 339.625432 -281.59202)
					(end 340.283292 -281.59202)
				)
			)
		)
	)
	(zone
		(layers "F.Cu" "B.Cu" "In1.Cu" "In2.Cu" "In3.Cu" "In4.Cu" "In5.Cu" "In6.Cu"
			"In7.Cu" "In8.Cu" "In9.Cu" "In10.Cu" "In11.Cu" "In12.Cu" "In13.Cu" "In14.Cu"
			"In15.Cu" "In16.Cu"
		)
		(hatch none 0.5)
		(connect_pads
			(clearance 0)
		)
		(min_thickness 0.25)
		(keepout
			(tracks not_allowed)
			(vias allowed)
			(pads allowed)
			(copperpour not_allowed)
			(footprints allowed)
		)
		(placement
			(enabled no)
			(sheetname "")
		)
		(fill
			(thermal_gap 0.5)
			(thermal_bridge_width 0.5)
			(island_removal_mode 0)
		)
		(polygon
			(pts
				(arc
					(start 128.415542 -223.575626)
					(mid 127.757682 -223.575626)
					(end 128.415542 -223.575626)
				)
			)
		)
	)
	(zone
		(layers "F.Cu" "B.Cu" "In1.Cu" "In2.Cu" "In3.Cu" "In4.Cu" "In5.Cu" "In6.Cu"
			"In7.Cu" "In8.Cu" "In9.Cu" "In10.Cu" "In11.Cu" "In12.Cu" "In13.Cu" "In14.Cu"
			"In15.Cu" "In16.Cu"
		)
		(hatch none 0.5)
		(connect_pads
			(clearance 0)
		)
		(min_thickness 0.25)
		(keepout
			(tracks not_allowed)
			(vias allowed)
			(pads allowed)
			(copperpour not_allowed)
			(footprints allowed)
		)
		(placement
			(enabled no)
			(sheetname "")
		)
		(fill
			(thermal_gap 0.5)
			(thermal_bridge_width 0.5)
			(island_removal_mode 0)
		)
		(polygon
			(pts
				(arc
					(start 133.114542 -218.692222)
					(mid 132.456682 -218.692222)
					(end 133.114542 -218.692222)
				)
			)
		)
	)
	(zone
		(layers "F.Cu" "B.Cu" "In1.Cu" "In2.Cu" "In3.Cu" "In4.Cu" "In5.Cu" "In6.Cu"
			"In7.Cu" "In8.Cu" "In9.Cu" "In10.Cu" "In11.Cu" "In12.Cu" "In13.Cu" "In14.Cu"
			"In15.Cu" "In16.Cu"
		)
		(hatch none 0.5)
		(connect_pads
			(clearance 0)
		)
		(min_thickness 0.25)
		(keepout
			(tracks not_allowed)
			(vias allowed)
			(pads allowed)
			(copperpour not_allowed)
			(footprints allowed)
		)
		(placement
			(enabled no)
			(sheetname "")
		)
		(fill
			(thermal_gap 0.5)
			(thermal_bridge_width 0.5)
			(island_removal_mode 0)
		)
		(polygon
			(pts
				(arc
					(start 358.499664 -221.94774)
					(mid 357.841804 -221.94774)
					(end 358.499664 -221.94774)
				)
			)
		)
	)
	(zone
		(layers "F.Cu" "B.Cu" "In1.Cu" "In2.Cu" "In3.Cu" "In4.Cu" "In5.Cu" "In6.Cu"
			"In7.Cu" "In8.Cu" "In9.Cu" "In10.Cu" "In11.Cu" "In12.Cu" "In13.Cu" "In14.Cu"
			"In15.Cu" "In16.Cu"
		)
		(hatch none 0.5)
		(connect_pads
			(clearance 0)
		)
		(min_thickness 0.25)
		(keepout
			(tracks not_allowed)
			(vias allowed)
			(pads allowed)
			(copperpour not_allowed)
			(footprints allowed)
		)
		(placement
			(enabled no)
			(sheetname "")
		)
		(fill
			(thermal_gap 0.5)
			(thermal_bridge_width 0.5)
			(island_removal_mode 0)
		)
		(polygon
			(pts
				(arc
					(start 106.800142 -225.203258)
					(mid 106.142282 -225.203258)
					(end 106.800142 -225.203258)
				)
			)
		)
	)
	(zone
		(layers "F.Cu" "B.Cu" "In1.Cu" "In2.Cu" "In3.Cu" "In4.Cu" "In5.Cu" "In6.Cu"
			"In7.Cu" "In8.Cu" "In9.Cu" "In10.Cu" "In11.Cu" "In12.Cu" "In13.Cu" "In14.Cu"
			"In15.Cu" "In16.Cu"
		)
		(hatch none 0.5)
		(connect_pads
			(clearance 0)
		)
		(min_thickness 0.25)
		(keepout
			(tracks not_allowed)
			(vias allowed)
			(pads allowed)
			(copperpour not_allowed)
			(footprints allowed)
		)
		(placement
			(enabled no)
			(sheetname "")
		)
		(fill
			(thermal_gap 0.5)
			(thermal_bridge_width 0.5)
			(island_removal_mode 0)
		)
		(polygon
			(pts
				(arc
					(start 353.17176 -214.720932)
					(mid 353.191444 -214.673522)
					(end 353.198176 -214.622634)
				)
				(arc
					(start 353.198176 -214.622634)
					(mid 353.14052 -214.48344)
					(end 353.001326 -214.425784)
				)
				(arc
					(start 353.001326 -214.425784)
					(mid 352.902895 -214.4522)
					(end 352.830892 -214.524336)
				)
				(arc
					(start 352.361246 -215.338406)
					(mid 352.341562 -215.385816)
					(end 352.33483 -215.436704)
				)
				(arc
					(start 352.33483 -215.436704)
					(mid 352.392486 -215.575898)
					(end 352.53168 -215.633554)
				)
				(arc
					(start 352.53168 -215.633554)
					(mid 352.630111 -215.607138)
					(end 352.702114 -215.535002)
				)
			)
		)
	)
	(zone
		(layers "F.Cu" "B.Cu" "In1.Cu" "In2.Cu" "In3.Cu" "In4.Cu" "In5.Cu" "In6.Cu"
			"In7.Cu" "In8.Cu" "In9.Cu" "In10.Cu" "In11.Cu" "In12.Cu" "In13.Cu" "In14.Cu"
			"In15.Cu" "In16.Cu"
		)
		(hatch none 0.5)
		(connect_pads
			(clearance 0)
		)
		(min_thickness 0.25)
		(keepout
			(tracks not_allowed)
			(vias allowed)
			(pads allowed)
			(copperpour not_allowed)
			(footprints allowed)
		)
		(placement
			(enabled no)
			(sheetname "")
		)
		(fill
			(thermal_gap 0.5)
			(thermal_bridge_width 0.5)
			(island_removal_mode 0)
		)
		(polygon
			(pts
				(arc
					(start 127.005588 -214.622634)
					(mid 126.347728 -214.622634)
					(end 127.005588 -214.622634)
				)
			)
		)
	)
	(zone
		(layers "F.Cu" "B.Cu" "In1.Cu" "In2.Cu" "In3.Cu" "In4.Cu" "In5.Cu" "In6.Cu"
			"In7.Cu" "In8.Cu" "In9.Cu" "In10.Cu" "In11.Cu" "In12.Cu" "In13.Cu" "In14.Cu"
			"In15.Cu" "In16.Cu"
		)
		(hatch none 0.5)
		(connect_pads
			(clearance 0)
		)
		(min_thickness 0.25)
		(keepout
			(tracks not_allowed)
			(vias allowed)
			(pads allowed)
			(copperpour not_allowed)
			(footprints allowed)
		)
		(placement
			(enabled no)
			(sheetname "")
		)
		(fill
			(thermal_gap 0.5)
			(thermal_bridge_width 0.5)
			(island_removal_mode 0)
		)
		(polygon
			(pts
				(arc
					(start 128.7272 -224.291144)
					(mid 128.655211 -224.218985)
					(end 128.556766 -224.192592)
				)
				(arc
					(start 128.556766 -224.192592)
					(mid 128.417572 -224.250248)
					(end 128.359916 -224.389442)
				)
				(arc
					(start 128.359916 -224.389442)
					(mid 128.366673 -224.440323)
					(end 128.386332 -224.48774)
				)
				(arc
					(start 128.855978 -225.301556)
					(mid 128.927967 -225.373715)
					(end 129.026412 -225.400108)
				)
				(arc
					(start 129.026412 -225.400108)
					(mid 129.165606 -225.342452)
					(end 129.223262 -225.203258)
				)
				(arc
					(start 129.223262 -225.203258)
					(mid 129.216505 -225.152377)
					(end 129.196846 -225.10496)
				)
			)
		)
	)
	(zone
		(layers "F.Cu" "B.Cu" "In1.Cu" "In2.Cu" "In3.Cu" "In4.Cu" "In5.Cu" "In6.Cu"
			"In7.Cu" "In8.Cu" "In9.Cu" "In10.Cu" "In11.Cu" "In12.Cu" "In13.Cu" "In14.Cu"
			"In15.Cu" "In16.Cu"
		)
		(hatch none 0.5)
		(connect_pads
			(clearance 0)
		)
		(min_thickness 0.25)
		(keepout
			(tracks not_allowed)
			(vias allowed)
			(pads allowed)
			(copperpour not_allowed)
			(footprints allowed)
		)
		(placement
			(enabled no)
			(sheetname "")
		)
		(fill
			(thermal_gap 0.5)
			(thermal_bridge_width 0.5)
			(island_removal_mode 0)
		)
		(polygon
			(pts
				(arc
					(start 124.656342 -217.064336)
					(mid 123.998482 -217.064336)
					(end 124.656342 -217.064336)
				)
			)
		)
	)
	(zone
		(layers "F.Cu" "B.Cu" "In1.Cu" "In2.Cu" "In3.Cu" "In4.Cu" "In5.Cu" "In6.Cu"
			"In7.Cu" "In8.Cu" "In9.Cu" "In10.Cu" "In11.Cu" "In12.Cu" "In13.Cu" "In14.Cu"
			"In15.Cu" "In16.Cu"
		)
		(hatch none 0.5)
		(connect_pads
			(clearance 0)
		)
		(min_thickness 0.25)
		(keepout
			(tracks not_allowed)
			(vias allowed)
			(pads allowed)
			(copperpour not_allowed)
			(footprints allowed)
		)
		(placement
			(enabled no)
			(sheetname "")
		)
		(fill
			(thermal_gap 0.5)
			(thermal_bridge_width 0.5)
			(island_removal_mode 0)
		)
		(polygon
			(pts
				(xy 470.499948 -110.470696) (xy 470.499948 -105.470706) (xy 470.804748 -105.775506) (xy 470.804748 -110.165896)
			)
		)
	)
	(zone
		(layers "F.Cu" "B.Cu" "In1.Cu" "In2.Cu" "In3.Cu" "In4.Cu" "In5.Cu" "In6.Cu"
			"In7.Cu" "In8.Cu" "In9.Cu" "In10.Cu" "In11.Cu" "In12.Cu" "In13.Cu" "In14.Cu"
			"In15.Cu" "In16.Cu"
		)
		(hatch none 0.5)
		(connect_pads
			(clearance 0)
		)
		(min_thickness 0.25)
		(keepout
			(tracks not_allowed)
			(vias allowed)
			(pads allowed)
			(copperpour not_allowed)
			(footprints allowed)
		)
		(placement
			(enabled no)
			(sheetname "")
		)
		(fill
			(thermal_gap 0.5)
			(thermal_bridge_width 0.5)
			(island_removal_mode 0)
		)
		(polygon
			(pts
				(arc
					(start 227.79736 -126.462028)
					(mid 227.41636 -126.081028)
					(end 227.03536 -126.462028)
				)
				(arc
					(start 227.03536 -127.325628)
					(mid 227.41636 -127.706628)
					(end 227.79736 -127.325628)
				)
			)
		)
	)
	(zone
		(layers "F.Cu" "B.Cu" "In1.Cu" "In2.Cu" "In3.Cu" "In4.Cu" "In5.Cu" "In6.Cu"
			"In7.Cu" "In8.Cu" "In9.Cu" "In10.Cu" "In11.Cu" "In12.Cu" "In13.Cu" "In14.Cu"
			"In15.Cu" "In16.Cu"
		)
		(hatch none 0.5)
		(connect_pads
			(clearance 0)
		)
		(min_thickness 0.25)
		(keepout
			(tracks not_allowed)
			(vias allowed)
			(pads allowed)
			(copperpour not_allowed)
			(footprints allowed)
		)
		(placement
			(enabled no)
			(sheetname "")
		)
		(fill
			(thermal_gap 0.5)
			(thermal_bridge_width 0.5)
			(island_removal_mode 0)
		)
		(polygon
			(pts
				(arc
					(start 374.317514 -223.67367)
					(mid 374.337198 -223.62626)
					(end 374.34393 -223.575372)
				)
				(arc
					(start 374.34393 -223.575372)
					(mid 374.286274 -223.436178)
					(end 374.14708 -223.378522)
				)
				(arc
					(start 374.14708 -223.378522)
					(mid 374.048649 -223.404938)
					(end 373.976646 -223.477074)
				)
				(arc
					(start 373.507 -224.291144)
					(mid 373.487316 -224.338554)
					(end 373.480584 -224.389442)
				)
				(arc
					(start 373.480584 -224.389442)
					(mid 373.53824 -224.528636)
					(end 373.677434 -224.586292)
				)
				(arc
					(start 373.677434 -224.586292)
					(mid 373.775865 -224.559876)
					(end 373.847868 -224.48774)
				)
			)
		)
	)
	(zone
		(layers "F.Cu" "B.Cu" "In1.Cu" "In2.Cu" "In3.Cu" "In4.Cu" "In5.Cu" "In6.Cu"
			"In7.Cu" "In8.Cu" "In9.Cu" "In10.Cu" "In11.Cu" "In12.Cu" "In13.Cu" "In14.Cu"
			"In15.Cu" "In16.Cu"
		)
		(hatch none 0.5)
		(connect_pads
			(clearance 0)
		)
		(min_thickness 0.25)
		(keepout
			(tracks not_allowed)
			(vias allowed)
			(pads allowed)
			(copperpour not_allowed)
			(footprints allowed)
		)
		(placement
			(enabled no)
			(sheetname "")
		)
		(fill
			(thermal_gap 0.5)
			(thermal_bridge_width 0.5)
			(island_removal_mode 0)
		)
		(polygon
			(pts
				(arc
					(start 374.831356 -171.701968)
					(mid 375.190566 -171.553178)
					(end 375.339356 -171.193968)
				)
				(arc
					(start 375.339356 -171.193968)
					(mid 375.271299 -170.939971)
					(end 375.085356 -170.75404)
				)
				(arc
					(start 374.161304 -170.220386)
					(mid 374.03901 -170.169849)
					(end 373.907812 -170.152568)
				)
				(arc
					(start 373.907304 -170.152568)
					(mid 373.548094 -170.301358)
					(end 373.399304 -170.660568)
				)
				(arc
					(start 373.399304 -170.660568)
					(mid 373.467361 -170.914565)
					(end 373.653304 -171.100496)
				)
				(arc
					(start 374.577356 -171.63415)
					(mid 374.69965 -171.684687)
					(end 374.830848 -171.701968)
				)
			)
		)
	)
	(zone
		(layers "F.Cu" "B.Cu" "In1.Cu" "In2.Cu" "In3.Cu" "In4.Cu" "In5.Cu" "In6.Cu"
			"In7.Cu" "In8.Cu" "In9.Cu" "In10.Cu" "In11.Cu" "In12.Cu" "In13.Cu" "In14.Cu"
			"In15.Cu" "In16.Cu"
		)
		(hatch none 0.5)
		(connect_pads
			(clearance 0)
		)
		(min_thickness 0.25)
		(keepout
			(tracks not_allowed)
			(vias allowed)
			(pads allowed)
			(copperpour not_allowed)
			(footprints allowed)
		)
		(placement
			(enabled no)
			(sheetname "")
		)
		(fill
			(thermal_gap 0.5)
			(thermal_bridge_width 0.5)
			(island_removal_mode 0)
		)
		(polygon
			(pts
				(arc
					(start 344.714068 -217.780108)
					(mid 344.642079 -217.707949)
					(end 344.543634 -217.681556)
				)
				(arc
					(start 344.543634 -217.681556)
					(mid 344.40444 -217.739212)
					(end 344.346784 -217.878406)
				)
				(arc
					(start 344.346784 -217.878406)
					(mid 344.353541 -217.929287)
					(end 344.3732 -217.976704)
				)
				(arc
					(start 344.842846 -218.79052)
					(mid 344.914835 -218.862679)
					(end 345.01328 -218.889072)
				)
				(arc
					(start 345.01328 -218.889072)
					(mid 345.152474 -218.831416)
					(end 345.21013 -218.692222)
				)
				(arc
					(start 345.21013 -218.692222)
					(mid 345.203373 -218.641341)
					(end 345.183714 -218.593924)
				)
			)
		)
	)
	(zone
		(layers "F.Cu" "B.Cu" "In1.Cu" "In2.Cu" "In3.Cu" "In4.Cu" "In5.Cu" "In6.Cu"
			"In7.Cu" "In8.Cu" "In9.Cu" "In10.Cu" "In11.Cu" "In12.Cu" "In13.Cu" "In14.Cu"
			"In15.Cu" "In16.Cu"
		)
		(hatch none 0.5)
		(connect_pads
			(clearance 0)
		)
		(min_thickness 0.25)
		(keepout
			(tracks not_allowed)
			(vias allowed)
			(pads allowed)
			(copperpour not_allowed)
			(footprints allowed)
		)
		(placement
			(enabled no)
			(sheetname "")
		)
		(fill
			(thermal_gap 0.5)
			(thermal_bridge_width 0.5)
			(island_removal_mode 0)
		)
		(polygon
			(pts
				(arc
					(start 130.875278 -288.103056)
					(mid 130.217418 -288.103056)
					(end 130.875278 -288.103056)
				)
			)
		)
	)
	(zone
		(layers "F.Cu" "B.Cu" "In1.Cu" "In2.Cu" "In3.Cu" "In4.Cu" "In5.Cu" "In6.Cu"
			"In7.Cu" "In8.Cu" "In9.Cu" "In10.Cu" "In11.Cu" "In12.Cu" "In13.Cu" "In14.Cu"
			"In15.Cu" "In16.Cu"
		)
		(hatch none 0.5)
		(connect_pads
			(clearance 0)
		)
		(min_thickness 0.25)
		(keepout
			(tracks not_allowed)
			(vias allowed)
			(pads allowed)
			(copperpour not_allowed)
			(footprints allowed)
		)
		(placement
			(enabled no)
			(sheetname "")
		)
		(fill
			(thermal_gap 0.5)
			(thermal_bridge_width 0.5)
			(island_removal_mode 0)
		)
		(polygon
			(pts
				(arc
					(start 102.963218 -276.708616)
					(mid 103.621078 -276.708616)
					(end 102.963218 -276.708616)
				)
			)
		)
	)
	(zone
		(layers "F.Cu" "B.Cu" "In1.Cu" "In2.Cu" "In3.Cu" "In4.Cu" "In5.Cu" "In6.Cu"
			"In7.Cu" "In8.Cu" "In9.Cu" "In10.Cu" "In11.Cu" "In12.Cu" "In13.Cu" "In14.Cu"
			"In15.Cu" "In16.Cu"
		)
		(hatch none 0.5)
		(connect_pads
			(clearance 0)
		)
		(min_thickness 0.25)
		(keepout
			(tracks not_allowed)
			(vias allowed)
			(pads allowed)
			(copperpour not_allowed)
			(footprints allowed)
		)
		(placement
			(enabled no)
			(sheetname "")
		)
		(fill
			(thermal_gap 0.5)
			(thermal_bridge_width 0.5)
			(island_removal_mode 0)
		)
		(polygon
			(pts
				(arc
					(start 334.612488 -400.477228)
					(mid 334.231488 -400.858228)
					(end 334.612488 -401.239228)
				)
				(arc
					(start 335.476088 -401.239228)
					(mid 335.857088 -400.858228)
					(end 335.476088 -400.477228)
				)
			)
		)
	)
	(zone
		(layers "F.Cu" "B.Cu" "In1.Cu" "In2.Cu" "In3.Cu" "In4.Cu" "In5.Cu" "In6.Cu"
			"In7.Cu" "In8.Cu" "In9.Cu" "In10.Cu" "In11.Cu" "In12.Cu" "In13.Cu" "In14.Cu"
			"In15.Cu" "In16.Cu"
		)
		(hatch none 0.5)
		(connect_pads
			(clearance 0)
		)
		(min_thickness 0.25)
		(keepout
			(tracks not_allowed)
			(vias allowed)
			(pads allowed)
			(copperpour not_allowed)
			(footprints allowed)
		)
		(placement
			(enabled no)
			(sheetname "")
		)
		(fill
			(thermal_gap 0.5)
			(thermal_bridge_width 0.5)
			(island_removal_mode 0)
		)
		(polygon
			(pts
				(arc
					(start 102.18166 -276.610318)
					(mid 102.161976 -276.657728)
					(end 102.155244 -276.708616)
				)
				(arc
					(start 102.155244 -276.708616)
					(mid 102.2129 -276.84781)
					(end 102.352094 -276.905466)
				)
				(arc
					(start 102.352094 -276.905466)
					(mid 102.450525 -276.87905)
					(end 102.522528 -276.806914)
				)
				(arc
					(start 102.992428 -275.992844)
					(mid 103.012112 -275.945434)
					(end 103.018844 -275.894546)
				)
				(arc
					(start 103.018844 -275.894546)
					(mid 102.961188 -275.755352)
					(end 102.821994 -275.697696)
				)
				(arc
					(start 102.821994 -275.697696)
					(mid 102.723563 -275.724112)
					(end 102.65156 -275.796248)
				)
			)
		)
	)
	(zone
		(layers "F.Cu" "B.Cu" "In1.Cu" "In2.Cu" "In3.Cu" "In4.Cu" "In5.Cu" "In6.Cu"
			"In7.Cu" "In8.Cu" "In9.Cu" "In10.Cu" "In11.Cu" "In12.Cu" "In13.Cu" "In14.Cu"
			"In15.Cu" "In16.Cu"
		)
		(hatch none 0.5)
		(connect_pads
			(clearance 0)
		)
		(min_thickness 0.25)
		(keepout
			(tracks not_allowed)
			(vias allowed)
			(pads allowed)
			(copperpour not_allowed)
			(footprints allowed)
		)
		(placement
			(enabled no)
			(sheetname "")
		)
		(fill
			(thermal_gap 0.5)
			(thermal_bridge_width 0.5)
			(island_removal_mode 0)
		)
		(polygon
			(pts
				(arc
					(start 131.546092 -221.231968)
					(mid 131.565776 -221.184558)
					(end 131.572508 -221.13367)
				)
				(arc
					(start 131.572508 -221.13367)
					(mid 131.514852 -220.994476)
					(end 131.375658 -220.93682)
				)
				(arc
					(start 131.375658 -220.93682)
					(mid 131.277227 -220.963236)
					(end 131.205224 -221.035372)
				)
				(arc
					(start 130.735578 -221.849442)
					(mid 130.715894 -221.896852)
					(end 130.709162 -221.94774)
				)
				(arc
					(start 130.709162 -221.94774)
					(mid 130.766818 -222.086934)
					(end 130.906012 -222.14459)
				)
				(arc
					(start 130.906012 -222.14459)
					(mid 131.004443 -222.118174)
					(end 131.076446 -222.046038)
				)
			)
		)
	)
	(zone
		(layers "F.Cu" "B.Cu" "In1.Cu" "In2.Cu" "In3.Cu" "In4.Cu" "In5.Cu" "In6.Cu"
			"In7.Cu" "In8.Cu" "In9.Cu" "In10.Cu" "In11.Cu" "In12.Cu" "In13.Cu" "In14.Cu"
			"In15.Cu" "In16.Cu"
		)
		(hatch none 0.5)
		(connect_pads
			(clearance 0)
		)
		(min_thickness 0.25)
		(keepout
			(tracks not_allowed)
			(vias allowed)
			(pads allowed)
			(copperpour not_allowed)
			(footprints allowed)
		)
		(placement
			(enabled no)
			(sheetname "")
		)
		(fill
			(thermal_gap 0.5)
			(thermal_bridge_width 0.5)
			(island_removal_mode 0)
		)
		(polygon
			(pts
				(arc
					(start 95.992696 -217.878406)
					(mid 95.334836 -217.878406)
					(end 95.992696 -217.878406)
				)
			)
		)
	)
	(zone
		(layers "F.Cu" "B.Cu" "In1.Cu" "In2.Cu" "In3.Cu" "In4.Cu" "In5.Cu" "In6.Cu"
			"In7.Cu" "In8.Cu" "In9.Cu" "In10.Cu" "In11.Cu" "In12.Cu" "In13.Cu" "In14.Cu"
			"In15.Cu" "In16.Cu"
		)
		(hatch none 0.5)
		(connect_pads
			(clearance 0)
		)
		(min_thickness 0.25)
		(keepout
			(tracks not_allowed)
			(vias allowed)
			(pads allowed)
			(copperpour not_allowed)
			(footprints allowed)
		)
		(placement
			(enabled no)
			(sheetname "")
		)
		(fill
			(thermal_gap 0.5)
			(thermal_bridge_width 0.5)
			(island_removal_mode 0)
		)
		(polygon
			(pts
				(arc
					(start 98.341942 -223.575626)
					(mid 97.684082 -223.575626)
					(end 98.341942 -223.575626)
				)
			)
		)
	)
	(zone
		(layers "F.Cu" "B.Cu" "In1.Cu" "In2.Cu" "In3.Cu" "In4.Cu" "In5.Cu" "In6.Cu"
			"In7.Cu" "In8.Cu" "In9.Cu" "In10.Cu" "In11.Cu" "In12.Cu" "In13.Cu" "In14.Cu"
			"In15.Cu" "In16.Cu"
		)
		(hatch none 0.5)
		(connect_pads
			(clearance 0)
		)
		(min_thickness 0.25)
		(keepout
			(tracks not_allowed)
			(vias allowed)
			(pads allowed)
			(copperpour not_allowed)
			(footprints allowed)
		)
		(placement
			(enabled no)
			(sheetname "")
		)
		(fill
			(thermal_gap 0.5)
			(thermal_bridge_width 0.5)
			(island_removal_mode 0)
		)
		(polygon
			(pts
				(arc
					(start 97.871788 -214.622634)
					(mid 97.213928 -214.622634)
					(end 97.871788 -214.622634)
				)
			)
		)
	)
	(zone
		(layers "F.Cu" "B.Cu" "In1.Cu" "In2.Cu" "In3.Cu" "In4.Cu" "In5.Cu" "In6.Cu"
			"In7.Cu" "In8.Cu" "In9.Cu" "In10.Cu" "In11.Cu" "In12.Cu" "In13.Cu" "In14.Cu"
			"In15.Cu" "In16.Cu"
		)
		(hatch none 0.5)
		(connect_pads
			(clearance 0)
		)
		(min_thickness 0.25)
		(keepout
			(tracks not_allowed)
			(vias allowed)
			(pads allowed)
			(copperpour not_allowed)
			(footprints allowed)
		)
		(placement
			(enabled no)
			(sheetname "")
		)
		(fill
			(thermal_gap 0.5)
			(thermal_bridge_width 0.5)
			(island_removal_mode 0)
		)
		(polygon
			(pts
				(arc
					(start 351.090992 -285.661354)
					(mid 350.433132 -285.661354)
					(end 351.090992 -285.661354)
				)
			)
		)
	)
	(zone
		(layers "F.Cu" "B.Cu" "In1.Cu" "In2.Cu" "In3.Cu" "In4.Cu" "In5.Cu" "In6.Cu"
			"In7.Cu" "In8.Cu" "In9.Cu" "In10.Cu" "In11.Cu" "In12.Cu" "In13.Cu" "In14.Cu"
			"In15.Cu" "In16.Cu"
		)
		(hatch none 0.5)
		(connect_pads
			(clearance 0)
		)
		(min_thickness 0.25)
		(keepout
			(tracks not_allowed)
			(vias allowed)
			(pads allowed)
			(copperpour not_allowed)
			(footprints allowed)
		)
		(placement
			(enabled no)
			(sheetname "")
		)
		(fill
			(thermal_gap 0.5)
			(thermal_bridge_width 0.5)
			(island_removal_mode 0)
		)
		(polygon
			(pts
				(arc
					(start 325.422768 -403.502876)
					(mid 325.041768 -403.883876)
					(end 325.422768 -404.264876)
				)
				(arc
					(start 326.286368 -404.264876)
					(mid 326.667368 -403.883876)
					(end 326.286368 -403.502876)
				)
			)
		)
	)
	(zone
		(layers "F.Cu" "B.Cu" "In1.Cu" "In2.Cu" "In3.Cu" "In4.Cu" "In5.Cu" "In6.Cu"
			"In7.Cu" "In8.Cu" "In9.Cu" "In10.Cu" "In11.Cu" "In12.Cu" "In13.Cu" "In14.Cu"
			"In15.Cu" "In16.Cu"
		)
		(hatch none 0.5)
		(connect_pads
			(clearance 0)
		)
		(min_thickness 0.25)
		(keepout
			(tracks not_allowed)
			(vias allowed)
			(pads allowed)
			(copperpour not_allowed)
			(footprints allowed)
		)
		(placement
			(enabled no)
			(sheetname "")
		)
		(fill
			(thermal_gap 0.5)
			(thermal_bridge_width 0.5)
			(island_removal_mode 0)
		)
		(polygon
			(pts
				(arc
					(start 342.52281 -217.064336)
					(mid 341.86495 -217.064336)
					(end 342.52281 -217.064336)
				)
			)
		)
	)
	(zone
		(layers "F.Cu" "B.Cu" "In1.Cu" "In2.Cu" "In3.Cu" "In4.Cu" "In5.Cu" "In6.Cu"
			"In7.Cu" "In8.Cu" "In9.Cu" "In10.Cu" "In11.Cu" "In12.Cu" "In13.Cu" "In14.Cu"
			"In15.Cu" "In16.Cu"
		)
		(hatch none 0.5)
		(connect_pads
			(clearance 0)
		)
		(min_thickness 0.25)
		(keepout
			(tracks not_allowed)
			(vias allowed)
			(pads allowed)
			(copperpour not_allowed)
			(footprints allowed)
		)
		(placement
			(enabled no)
			(sheetname "")
		)
		(fill
			(thermal_gap 0.5)
			(thermal_bridge_width 0.5)
			(island_removal_mode 0)
		)
		(polygon
			(pts
				(arc
					(start 343.802208 -400.477228)
					(mid 343.421208 -400.858228)
					(end 343.802208 -401.239228)
				)
				(arc
					(start 344.665808 -401.239228)
					(mid 345.046808 -400.858228)
					(end 344.665808 -400.477228)
				)
			)
		)
	)
	(zone
		(layers "F.Cu" "B.Cu" "In1.Cu" "In2.Cu" "In3.Cu" "In4.Cu" "In5.Cu" "In6.Cu"
			"In7.Cu" "In8.Cu" "In9.Cu" "In10.Cu" "In11.Cu" "In12.Cu" "In13.Cu" "In14.Cu"
			"In15.Cu" "In16.Cu"
		)
		(hatch none 0.5)
		(connect_pads
			(clearance 0)
		)
		(min_thickness 0.25)
		(keepout
			(tracks not_allowed)
			(vias allowed)
			(pads allowed)
			(copperpour not_allowed)
			(footprints allowed)
		)
		(placement
			(enabled no)
			(sheetname "")
		)
		(fill
			(thermal_gap 0.5)
			(thermal_bridge_width 0.5)
			(island_removal_mode 0)
		)
		(polygon
			(pts
				(arc
					(start 19.016726 -6.343396)
					(mid 18.635726 -6.724396)
					(end 19.016726 -7.105396)
				)
				(arc
					(start 19.880326 -7.105396)
					(mid 20.261326 -6.724396)
					(end 19.880326 -6.343396)
				)
			)
		)
	)
	(zone
		(layers "F.Cu" "B.Cu" "In1.Cu" "In2.Cu" "In3.Cu" "In4.Cu" "In5.Cu" "In6.Cu"
			"In7.Cu" "In8.Cu" "In9.Cu" "In10.Cu" "In11.Cu" "In12.Cu" "In13.Cu" "In14.Cu"
			"In15.Cu" "In16.Cu"
		)
		(hatch none 0.5)
		(connect_pads
			(clearance 0)
		)
		(min_thickness 0.25)
		(keepout
			(tracks not_allowed)
			(vias allowed)
			(pads allowed)
			(copperpour not_allowed)
			(footprints allowed)
		)
		(placement
			(enabled no)
			(sheetname "")
		)
		(fill
			(thermal_gap 0.5)
			(thermal_bridge_width 0.5)
			(island_removal_mode 0)
		)
		(polygon
			(pts
				(arc
					(start 100.5332 -221.035626)
					(mid 100.461211 -220.963467)
					(end 100.362766 -220.937074)
				)
				(arc
					(start 100.362766 -220.937074)
					(mid 100.223572 -220.99473)
					(end 100.165916 -221.133924)
				)
				(arc
					(start 100.165916 -221.133924)
					(mid 100.172673 -221.184805)
					(end 100.192332 -221.232222)
				)
				(arc
					(start 100.661978 -222.046038)
					(mid 100.733967 -222.118197)
					(end 100.832412 -222.14459)
				)
				(arc
					(start 100.832412 -222.14459)
					(mid 100.971606 -222.086934)
					(end 101.029262 -221.94774)
				)
				(arc
					(start 101.029262 -221.94774)
					(mid 101.022505 -221.896859)
					(end 101.002846 -221.849442)
				)
			)
		)
	)
	(zone
		(layers "F.Cu" "B.Cu" "In1.Cu" "In2.Cu" "In3.Cu" "In4.Cu" "In5.Cu" "In6.Cu"
			"In7.Cu" "In8.Cu" "In9.Cu" "In10.Cu" "In11.Cu" "In12.Cu" "In13.Cu" "In14.Cu"
			"In15.Cu" "In16.Cu"
		)
		(hatch none 0.5)
		(connect_pads
			(clearance 0)
		)
		(min_thickness 0.25)
		(keepout
			(tracks not_allowed)
			(vias allowed)
			(pads allowed)
			(copperpour not_allowed)
			(footprints allowed)
		)
		(placement
			(enabled no)
			(sheetname "")
		)
		(fill
			(thermal_gap 0.5)
			(thermal_bridge_width 0.5)
			(island_removal_mode 0)
		)
		(polygon
			(pts
				(arc
					(start 148.162772 -251.76988)
					(mid 143.716756 -251.76988)
					(end 148.162772 -251.76988)
				)
			)
		)
	)
	(zone
		(layers "F.Cu" "B.Cu" "In1.Cu" "In2.Cu" "In3.Cu" "In4.Cu" "In5.Cu" "In6.Cu"
			"In7.Cu" "In8.Cu" "In9.Cu" "In10.Cu" "In11.Cu" "In12.Cu" "In13.Cu" "In14.Cu"
			"In15.Cu" "In16.Cu"
		)
		(hatch none 0.5)
		(connect_pads
			(clearance 0)
		)
		(min_thickness 0.25)
		(keepout
			(tracks not_allowed)
			(vias allowed)
			(pads allowed)
			(copperpour not_allowed)
			(footprints allowed)
		)
		(placement
			(enabled no)
			(sheetname "")
		)
		(fill
			(thermal_gap 0.5)
			(thermal_bridge_width 0.5)
			(island_removal_mode 0)
		)
		(polygon
			(pts
				(arc
					(start 115.727988 -214.622634)
					(mid 115.070128 -214.622634)
					(end 115.727988 -214.622634)
				)
			)
		)
	)
	(zone
		(layers "F.Cu" "B.Cu" "In1.Cu" "In2.Cu" "In3.Cu" "In4.Cu" "In5.Cu" "In6.Cu"
			"In7.Cu" "In8.Cu" "In9.Cu" "In10.Cu" "In11.Cu" "In12.Cu" "In13.Cu" "In14.Cu"
			"In15.Cu" "In16.Cu"
		)
		(hatch none 0.5)
		(connect_pads
			(clearance 0)
		)
		(min_thickness 0.25)
		(keepout
			(tracks not_allowed)
			(vias allowed)
			(pads allowed)
			(copperpour not_allowed)
			(footprints allowed)
		)
		(placement
			(enabled no)
			(sheetname "")
		)
		(fill
			(thermal_gap 0.5)
			(thermal_bridge_width 0.5)
			(island_removal_mode 0)
		)
		(polygon
			(pts
				(arc
					(start 138.534394 -400.477228)
					(mid 138.153394 -400.858228)
					(end 138.534394 -401.239228)
				)
				(arc
					(start 139.397994 -401.239228)
					(mid 139.778994 -400.858228)
					(end 139.397994 -400.477228)
				)
			)
		)
	)
	(zone
		(layers "F.Cu" "B.Cu" "In1.Cu" "In2.Cu" "In3.Cu" "In4.Cu" "In5.Cu" "In6.Cu"
			"In7.Cu" "In8.Cu" "In9.Cu" "In10.Cu" "In11.Cu" "In12.Cu" "In13.Cu" "In14.Cu"
			"In15.Cu" "In16.Cu"
		)
		(hatch none 0.5)
		(connect_pads
			(clearance 0)
		)
		(min_thickness 0.25)
		(keepout
			(tracks not_allowed)
			(vias allowed)
			(pads allowed)
			(copperpour not_allowed)
			(footprints allowed)
		)
		(placement
			(enabled no)
			(sheetname "")
		)
		(fill
			(thermal_gap 0.5)
			(thermal_bridge_width 0.5)
			(island_removal_mode 0)
		)
		(polygon
			(pts
				(arc
					(start 341.693246 -282.405836)
					(mid 341.035386 -282.405836)
					(end 341.693246 -282.405836)
				)
			)
		)
	)
	(zone
		(layers "F.Cu" "B.Cu" "In1.Cu" "In2.Cu" "In3.Cu" "In4.Cu" "In5.Cu" "In6.Cu"
			"In7.Cu" "In8.Cu" "In9.Cu" "In10.Cu" "In11.Cu" "In12.Cu" "In13.Cu" "In14.Cu"
			"In15.Cu" "In16.Cu"
		)
		(hatch none 0.5)
		(connect_pads
			(clearance 0)
		)
		(min_thickness 0.25)
		(keepout
			(tracks not_allowed)
			(vias allowed)
			(pads allowed)
			(copperpour not_allowed)
			(footprints allowed)
		)
		(placement
			(enabled no)
			(sheetname "")
		)
		(fill
			(thermal_gap 0.5)
			(thermal_bridge_width 0.5)
			(island_removal_mode 0)
		)
		(polygon
			(pts
				(arc
					(start 378.65685 -284.74924)
					(mid 378.584861 -284.677081)
					(end 378.486416 -284.650688)
				)
				(arc
					(start 378.486416 -284.650688)
					(mid 378.347222 -284.708344)
					(end 378.289566 -284.847538)
				)
				(arc
					(start 378.289566 -284.847538)
					(mid 378.296323 -284.898419)
					(end 378.315982 -284.945836)
				)
				(arc
					(start 378.785628 -285.759652)
					(mid 378.857617 -285.831811)
					(end 378.956062 -285.858204)
				)
				(arc
					(start 378.956062 -285.858204)
					(mid 379.095256 -285.800548)
					(end 379.152912 -285.661354)
				)
				(arc
					(start 379.152912 -285.661354)
					(mid 379.146155 -285.610473)
					(end 379.126496 -285.563056)
				)
			)
		)
	)
	(zone
		(layers "F.Cu" "B.Cu" "In1.Cu" "In2.Cu" "In3.Cu" "In4.Cu" "In5.Cu" "In6.Cu"
			"In7.Cu" "In8.Cu" "In9.Cu" "In10.Cu" "In11.Cu" "In12.Cu" "In13.Cu" "In14.Cu"
			"In15.Cu" "In16.Cu"
		)
		(hatch none 0.5)
		(connect_pads
			(clearance 0)
		)
		(min_thickness 0.25)
		(keepout
			(tracks not_allowed)
			(vias allowed)
			(pads allowed)
			(copperpour not_allowed)
			(footprints allowed)
		)
		(placement
			(enabled no)
			(sheetname "")
		)
		(fill
			(thermal_gap 0.5)
			(thermal_bridge_width 0.5)
			(island_removal_mode 0)
		)
		(polygon
			(pts
				(arc
					(start 380.11481 -217.064336)
					(mid 379.45695 -217.064336)
					(end 380.11481 -217.064336)
				)
			)
		)
	)
	(zone
		(layers "F.Cu" "B.Cu" "In1.Cu" "In2.Cu" "In3.Cu" "In4.Cu" "In5.Cu" "In6.Cu"
			"In7.Cu" "In8.Cu" "In9.Cu" "In10.Cu" "In11.Cu" "In12.Cu" "In13.Cu" "In14.Cu"
			"In15.Cu" "In16.Cu"
		)
		(hatch none 0.5)
		(connect_pads
			(clearance 0)
		)
		(min_thickness 0.25)
		(keepout
			(tracks not_allowed)
			(vias allowed)
			(pads allowed)
			(copperpour not_allowed)
			(footprints allowed)
		)
		(placement
			(enabled no)
			(sheetname "")
		)
		(fill
			(thermal_gap 0.5)
			(thermal_bridge_width 0.5)
			(island_removal_mode 0)
		)
		(polygon
			(pts
				(arc
					(start 361.788964 -221.133924)
					(mid 361.131104 -221.133924)
					(end 361.788964 -221.133924)
				)
			)
		)
	)
	(zone
		(layers "F.Cu" "B.Cu" "In1.Cu" "In2.Cu" "In3.Cu" "In4.Cu" "In5.Cu" "In6.Cu"
			"In7.Cu" "In8.Cu" "In9.Cu" "In10.Cu" "In11.Cu" "In12.Cu" "In13.Cu" "In14.Cu"
			"In15.Cu" "In16.Cu"
		)
		(hatch none 0.5)
		(connect_pads
			(clearance 0)
		)
		(min_thickness 0.25)
		(keepout
			(tracks not_allowed)
			(vias allowed)
			(pads allowed)
			(copperpour not_allowed)
			(footprints allowed)
		)
		(placement
			(enabled no)
			(sheetname "")
		)
		(fill
			(thermal_gap 0.5)
			(thermal_bridge_width 0.5)
			(island_removal_mode 0)
		)
		(polygon
			(pts
				(arc
					(start 352.500946 -281.59202)
					(mid 351.843086 -281.59202)
					(end 352.500946 -281.59202)
				)
			)
		)
	)
	(zone
		(layers "F.Cu" "B.Cu" "In1.Cu" "In2.Cu" "In3.Cu" "In4.Cu" "In5.Cu" "In6.Cu"
			"In7.Cu" "In8.Cu" "In9.Cu" "In10.Cu" "In11.Cu" "In12.Cu" "In13.Cu" "In14.Cu"
			"In15.Cu" "In16.Cu"
		)
		(hatch none 0.5)
		(connect_pads
			(clearance 0)
		)
		(min_thickness 0.25)
		(keepout
			(tracks not_allowed)
			(vias allowed)
			(pads allowed)
			(copperpour not_allowed)
			(footprints allowed)
		)
		(placement
			(enabled no)
			(sheetname "")
		)
		(fill
			(thermal_gap 0.5)
			(thermal_bridge_width 0.5)
			(island_removal_mode 0)
		)
		(polygon
			(pts
				(arc
					(start 92.544646 -220.418152)
					(mid 92.56433 -220.370742)
					(end 92.571062 -220.319854)
				)
				(arc
					(start 92.571062 -220.319854)
					(mid 92.513406 -220.18066)
					(end 92.374212 -220.123004)
				)
				(arc
					(start 92.374212 -220.123004)
					(mid 92.275781 -220.14942)
					(end 92.203778 -220.221556)
				)
				(arc
					(start 91.734132 -221.035626)
					(mid 91.714448 -221.083036)
					(end 91.707716 -221.133924)
				)
				(arc
					(start 91.707716 -221.133924)
					(mid 91.765372 -221.273118)
					(end 91.904566 -221.330774)
				)
				(arc
					(start 91.904566 -221.330774)
					(mid 92.002997 -221.304358)
					(end 92.075 -221.232222)
				)
			)
		)
	)
	(zone
		(layers "F.Cu" "B.Cu" "In1.Cu" "In2.Cu" "In3.Cu" "In4.Cu" "In5.Cu" "In6.Cu"
			"In7.Cu" "In8.Cu" "In9.Cu" "In10.Cu" "In11.Cu" "In12.Cu" "In13.Cu" "In14.Cu"
			"In15.Cu" "In16.Cu"
		)
		(hatch none 0.5)
		(connect_pads
			(clearance 0)
		)
		(min_thickness 0.25)
		(keepout
			(tracks not_allowed)
			(vias allowed)
			(pads allowed)
			(copperpour not_allowed)
			(footprints allowed)
		)
		(placement
			(enabled no)
			(sheetname "")
		)
		(fill
			(thermal_gap 0.5)
			(thermal_bridge_width 0.5)
			(island_removal_mode 0)
		)
		(polygon
			(pts
				(arc
					(start 127.116078 -288.103056)
					(mid 126.458218 -288.103056)
					(end 127.116078 -288.103056)
				)
			)
		)
	)
	(zone
		(layers "F.Cu" "B.Cu" "In1.Cu" "In2.Cu" "In3.Cu" "In4.Cu" "In5.Cu" "In6.Cu"
			"In7.Cu" "In8.Cu" "In9.Cu" "In10.Cu" "In11.Cu" "In12.Cu" "In13.Cu" "In14.Cu"
			"In15.Cu" "In16.Cu"
		)
		(hatch none 0.5)
		(connect_pads
			(clearance 0)
		)
		(min_thickness 0.25)
		(keepout
			(tracks not_allowed)
			(vias allowed)
			(pads allowed)
			(copperpour not_allowed)
			(footprints allowed)
		)
		(placement
			(enabled no)
			(sheetname "")
		)
		(fill
			(thermal_gap 0.5)
			(thermal_bridge_width 0.5)
			(island_removal_mode 0)
		)
		(polygon
			(pts
				(arc
					(start 360.849164 -224.389442)
					(mid 360.191304 -224.389442)
					(end 360.849164 -224.389442)
				)
			)
		)
	)
	(zone
		(layers "F.Cu" "B.Cu" "In1.Cu" "In2.Cu" "In3.Cu" "In4.Cu" "In5.Cu" "In6.Cu"
			"In7.Cu" "In8.Cu" "In9.Cu" "In10.Cu" "In11.Cu" "In12.Cu" "In13.Cu" "In14.Cu"
			"In15.Cu" "In16.Cu"
		)
		(hatch none 0.5)
		(connect_pads
			(clearance 0)
		)
		(min_thickness 0.25)
		(keepout
			(tracks not_allowed)
			(vias allowed)
			(pads allowed)
			(copperpour not_allowed)
			(footprints allowed)
		)
		(placement
			(enabled no)
			(sheetname "")
		)
		(fill
			(thermal_gap 0.5)
			(thermal_bridge_width 0.5)
			(island_removal_mode 0)
		)
		(polygon
			(pts
				(arc
					(start 352.86061 -218.692222)
					(mid 352.20275 -218.692222)
					(end 352.86061 -218.692222)
				)
			)
		)
	)
	(zone
		(layers "F.Cu" "B.Cu" "In1.Cu" "In2.Cu" "In3.Cu" "In4.Cu" "In5.Cu" "In6.Cu"
			"In7.Cu" "In8.Cu" "In9.Cu" "In10.Cu" "In11.Cu" "In12.Cu" "In13.Cu" "In14.Cu"
			"In15.Cu" "In16.Cu"
		)
		(hatch none 0.5)
		(connect_pads
			(clearance 0)
		)
		(min_thickness 0.25)
		(keepout
			(tracks not_allowed)
			(vias allowed)
			(pads allowed)
			(copperpour not_allowed)
			(footprints allowed)
		)
		(placement
			(enabled no)
			(sheetname "")
		)
		(fill
			(thermal_gap 0.5)
			(thermal_bridge_width 0.5)
			(island_removal_mode 0)
		)
		(polygon
			(pts
				(arc
					(start 377.29541 -221.94774)
					(mid 376.63755 -221.94774)
					(end 377.29541 -221.94774)
				)
			)
		)
	)
	(zone
		(layers "F.Cu" "B.Cu" "In1.Cu" "In2.Cu" "In3.Cu" "In4.Cu" "In5.Cu" "In6.Cu"
			"In7.Cu" "In8.Cu" "In9.Cu" "In10.Cu" "In11.Cu" "In12.Cu" "In13.Cu" "In14.Cu"
			"In15.Cu" "In16.Cu"
		)
		(hatch none 0.5)
		(connect_pads
			(clearance 0)
		)
		(min_thickness 0.25)
		(keepout
			(tracks not_allowed)
			(vias allowed)
			(pads allowed)
			(copperpour not_allowed)
			(footprints allowed)
		)
		(placement
			(enabled no)
			(sheetname "")
		)
		(fill
			(thermal_gap 0.5)
			(thermal_bridge_width 0.5)
			(island_removal_mode 0)
		)
		(polygon
			(pts
				(arc
					(start 101.71176 -282.307538)
					(mid 101.692076 -282.354948)
					(end 101.685344 -282.405836)
				)
				(arc
					(start 101.685344 -282.405836)
					(mid 101.743 -282.54503)
					(end 101.882194 -282.602686)
				)
				(arc
					(start 101.882194 -282.602686)
					(mid 101.980625 -282.57627)
					(end 102.052628 -282.504134)
				)
				(arc
					(start 102.522528 -281.690064)
					(mid 102.542212 -281.642654)
					(end 102.548944 -281.591766)
				)
				(arc
					(start 102.548944 -281.591766)
					(mid 102.491288 -281.452572)
					(end 102.352094 -281.394916)
				)
				(arc
					(start 102.352094 -281.394916)
					(mid 102.253663 -281.421332)
					(end 102.18166 -281.493468)
				)
			)
		)
	)
	(zone
		(layers "F.Cu" "B.Cu" "In1.Cu" "In2.Cu" "In3.Cu" "In4.Cu" "In5.Cu" "In6.Cu"
			"In7.Cu" "In8.Cu" "In9.Cu" "In10.Cu" "In11.Cu" "In12.Cu" "In13.Cu" "In14.Cu"
			"In15.Cu" "In16.Cu"
		)
		(hatch none 0.5)
		(connect_pads
			(clearance 0)
		)
		(min_thickness 0.25)
		(keepout
			(tracks not_allowed)
			(vias allowed)
			(pads allowed)
			(copperpour not_allowed)
			(footprints allowed)
		)
		(placement
			(enabled no)
			(sheetname "")
		)
		(fill
			(thermal_gap 0.5)
			(thermal_bridge_width 0.5)
			(island_removal_mode 0)
		)
		(polygon
			(pts
				(arc
					(start 352.799904 -187.756292)
					(mid 353.159114 -187.607502)
					(end 353.307904 -187.248292)
				)
				(arc
					(start 353.307904 -187.248292)
					(mid 353.239847 -186.994295)
					(end 353.053904 -186.808364)
				)
				(arc
					(start 352.129852 -186.27471)
					(mid 352.007558 -186.224173)
					(end 351.87636 -186.206892)
				)
				(arc
					(start 351.875852 -186.206892)
					(mid 351.516642 -186.355682)
					(end 351.367852 -186.714892)
				)
				(arc
					(start 351.367852 -186.714892)
					(mid 351.435909 -186.968889)
					(end 351.621852 -187.15482)
				)
				(arc
					(start 352.545904 -187.688474)
					(mid 352.668198 -187.739011)
					(end 352.799396 -187.756292)
				)
			)
		)
	)
	(zone
		(layers "F.Cu" "B.Cu" "In1.Cu" "In2.Cu" "In3.Cu" "In4.Cu" "In5.Cu" "In6.Cu"
			"In7.Cu" "In8.Cu" "In9.Cu" "In10.Cu" "In11.Cu" "In12.Cu" "In13.Cu" "In14.Cu"
			"In15.Cu" "In16.Cu"
		)
		(hatch none 0.5)
		(connect_pads
			(clearance 0)
		)
		(min_thickness 0.25)
		(keepout
			(tracks not_allowed)
			(vias allowed)
			(pads allowed)
			(copperpour not_allowed)
			(footprints allowed)
		)
		(placement
			(enabled no)
			(sheetname "")
		)
		(fill
			(thermal_gap 0.5)
			(thermal_bridge_width 0.5)
			(island_removal_mode 0)
		)
		(polygon
			(pts
				(arc
					(start 137.414508 -17.763744)
					(mid 137.033508 -18.144744)
					(end 137.414508 -18.525744)
				)
				(arc
					(start 138.278108 -18.525744)
					(mid 138.659108 -18.144744)
					(end 138.278108 -17.763744)
				)
			)
		)
	)
	(zone
		(layers "F.Cu" "B.Cu" "In1.Cu" "In2.Cu" "In3.Cu" "In4.Cu" "In5.Cu" "In6.Cu"
			"In7.Cu" "In8.Cu" "In9.Cu" "In10.Cu" "In11.Cu" "In12.Cu" "In13.Cu" "In14.Cu"
			"In15.Cu" "In16.Cu"
		)
		(hatch none 0.5)
		(connect_pads
			(clearance 0)
		)
		(min_thickness 0.25)
		(keepout
			(tracks not_allowed)
			(vias allowed)
			(pads allowed)
			(copperpour not_allowed)
			(footprints allowed)
		)
		(placement
			(enabled no)
			(sheetname "")
		)
		(fill
			(thermal_gap 0.5)
			(thermal_bridge_width 0.5)
			(island_removal_mode 0)
		)
		(polygon
			(pts
				(arc
					(start 125.048518 -288.917126)
					(mid 125.706378 -288.917126)
					(end 125.048518 -288.917126)
				)
			)
		)
	)
	(zone
		(layers "F.Cu" "B.Cu" "In1.Cu" "In2.Cu" "In3.Cu" "In4.Cu" "In5.Cu" "In6.Cu"
			"In7.Cu" "In8.Cu" "In9.Cu" "In10.Cu" "In11.Cu" "In12.Cu" "In13.Cu" "In14.Cu"
			"In15.Cu" "In16.Cu"
		)
		(hatch none 0.5)
		(connect_pads
			(clearance 0)
		)
		(min_thickness 0.25)
		(keepout
			(tracks not_allowed)
			(vias allowed)
			(pads allowed)
			(copperpour not_allowed)
			(footprints allowed)
		)
		(placement
			(enabled no)
			(sheetname "")
		)
		(fill
			(thermal_gap 0.5)
			(thermal_bridge_width 0.5)
			(island_removal_mode 0)
		)
		(polygon
			(pts
				(arc
					(start 374.585992 -285.661354)
					(mid 373.928132 -285.661354)
					(end 374.585992 -285.661354)
				)
			)
		)
	)
	(zone
		(layers "F.Cu" "B.Cu" "In1.Cu" "In2.Cu" "In3.Cu" "In4.Cu" "In5.Cu" "In6.Cu"
			"In7.Cu" "In8.Cu" "In9.Cu" "In10.Cu" "In11.Cu" "In12.Cu" "In13.Cu" "In14.Cu"
			"In15.Cu" "In16.Cu"
		)
		(hatch none 0.5)
		(connect_pads
			(clearance 0)
		)
		(min_thickness 0.25)
		(keepout
			(tracks not_allowed)
			(vias allowed)
			(pads allowed)
			(copperpour not_allowed)
			(footprints allowed)
		)
		(placement
			(enabled no)
			(sheetname "")
		)
		(fill
			(thermal_gap 0.5)
			(thermal_bridge_width 0.5)
			(island_removal_mode 0)
		)
		(polygon
			(pts
				(arc
					(start 127.945896 -224.389442)
					(mid 127.288036 -224.389442)
					(end 127.945896 -224.389442)
				)
			)
		)
	)
	(zone
		(layers "F.Cu" "B.Cu" "In1.Cu" "In2.Cu" "In3.Cu" "In4.Cu" "In5.Cu" "In6.Cu"
			"In7.Cu" "In8.Cu" "In9.Cu" "In10.Cu" "In11.Cu" "In12.Cu" "In13.Cu" "In14.Cu"
			"In15.Cu" "In16.Cu"
		)
		(hatch none 0.5)
		(connect_pads
			(clearance 0)
		)
		(min_thickness 0.25)
		(keepout
			(tracks not_allowed)
			(vias allowed)
			(pads allowed)
			(copperpour not_allowed)
			(footprints allowed)
		)
		(placement
			(enabled no)
			(sheetname "")
		)
		(fill
			(thermal_gap 0.5)
			(thermal_bridge_width 0.5)
			(island_removal_mode 0)
		)
		(polygon
			(pts
				(arc
					(start 133.998462 -289.003232)
					(mid 134.014386 -288.961481)
					(end 134.019798 -288.917126)
				)
				(arc
					(start 134.019798 -288.917126)
					(mid 133.965862 -288.786912)
					(end 133.835648 -288.732976)
				)
				(arc
					(start 133.835648 -288.732976)
					(mid 133.740628 -288.759384)
					(end 133.672834 -288.83102)
				)
				(arc
					(start 133.20268 -289.721036)
					(mid 133.186756 -289.762787)
					(end 133.181344 -289.807142)
				)
				(arc
					(start 133.181344 -289.807142)
					(mid 133.23528 -289.937356)
					(end 133.365494 -289.991292)
				)
				(arc
					(start 133.365494 -289.991292)
					(mid 133.460514 -289.964884)
					(end 133.528308 -289.893248)
				)
			)
		)
	)
	(zone
		(layers "F.Cu" "B.Cu" "In1.Cu" "In2.Cu" "In3.Cu" "In4.Cu" "In5.Cu" "In6.Cu"
			"In7.Cu" "In8.Cu" "In9.Cu" "In10.Cu" "In11.Cu" "In12.Cu" "In13.Cu" "In14.Cu"
			"In15.Cu" "In16.Cu"
		)
		(hatch none 0.5)
		(connect_pads
			(clearance 0)
		)
		(min_thickness 0.25)
		(keepout
			(tracks not_allowed)
			(vias allowed)
			(pads allowed)
			(copperpour not_allowed)
			(footprints allowed)
		)
		(placement
			(enabled no)
			(sheetname "")
		)
		(fill
			(thermal_gap 0.5)
			(thermal_bridge_width 0.5)
			(island_removal_mode 0)
		)
		(polygon
			(pts
				(arc
					(start 352.030792 -282.405836)
					(mid 351.372932 -282.405836)
					(end 352.030792 -282.405836)
				)
			)
		)
	)
	(zone
		(layers "F.Cu" "B.Cu" "In1.Cu" "In2.Cu" "In3.Cu" "In4.Cu" "In5.Cu" "In6.Cu"
			"In7.Cu" "In8.Cu" "In9.Cu" "In10.Cu" "In11.Cu" "In12.Cu" "In13.Cu" "In14.Cu"
			"In15.Cu" "In16.Cu"
		)
		(hatch none 0.5)
		(connect_pads
			(clearance 0)
		)
		(min_thickness 0.25)
		(keepout
			(tracks not_allowed)
			(vias allowed)
			(pads allowed)
			(copperpour not_allowed)
			(footprints allowed)
		)
		(placement
			(enabled no)
			(sheetname "")
		)
		(fill
			(thermal_gap 0.5)
			(thermal_bridge_width 0.5)
			(island_removal_mode 0)
		)
		(polygon
			(pts
				(xy 473.999814 -54.23662) (xy 473.999814 -49.23663) (xy 474.304614 -49.54143) (xy 474.304614 -53.93182)
			)
		)
	)
	(zone
		(layers "F.Cu" "B.Cu" "In1.Cu" "In2.Cu" "In3.Cu" "In4.Cu" "In5.Cu" "In6.Cu"
			"In7.Cu" "In8.Cu" "In9.Cu" "In10.Cu" "In11.Cu" "In12.Cu" "In13.Cu" "In14.Cu"
			"In15.Cu" "In16.Cu"
		)
		(hatch none 0.5)
		(connect_pads
			(clearance 0)
		)
		(min_thickness 0.25)
		(keepout
			(tracks not_allowed)
			(vias allowed)
			(pads allowed)
			(copperpour not_allowed)
			(footprints allowed)
		)
		(placement
			(enabled no)
			(sheetname "")
		)
		(fill
			(thermal_gap 0.5)
			(thermal_bridge_width 0.5)
			(island_removal_mode 0)
		)
		(polygon
			(pts
				(arc
					(start 105.312464 -280.778204)
					(mid 105.970324 -280.778204)
					(end 105.312464 -280.778204)
				)
			)
		)
	)
	(zone
		(layers "F.Cu" "B.Cu" "In1.Cu" "In2.Cu" "In3.Cu" "In4.Cu" "In5.Cu" "In6.Cu"
			"In7.Cu" "In8.Cu" "In9.Cu" "In10.Cu" "In11.Cu" "In12.Cu" "In13.Cu" "In14.Cu"
			"In15.Cu" "In16.Cu"
		)
		(hatch none 0.5)
		(connect_pads
			(clearance 0)
		)
		(min_thickness 0.25)
		(keepout
			(tracks not_allowed)
			(vias allowed)
			(pads allowed)
			(copperpour not_allowed)
			(footprints allowed)
		)
		(placement
			(enabled no)
			(sheetname "")
		)
		(fill
			(thermal_gap 0.5)
			(thermal_bridge_width 0.5)
			(island_removal_mode 0)
		)
		(polygon
			(pts
				(arc
					(start 108.990892 -214.720932)
					(mid 109.010576 -214.673522)
					(end 109.017308 -214.622634)
				)
				(arc
					(start 109.017308 -214.622634)
					(mid 108.959652 -214.48344)
					(end 108.820458 -214.425784)
				)
				(arc
					(start 108.820458 -214.425784)
					(mid 108.722027 -214.4522)
					(end 108.650024 -214.524336)
				)
				(arc
					(start 108.180378 -215.338406)
					(mid 108.160694 -215.385816)
					(end 108.153962 -215.436704)
				)
				(arc
					(start 108.153962 -215.436704)
					(mid 108.211618 -215.575898)
					(end 108.350812 -215.633554)
				)
				(arc
					(start 108.350812 -215.633554)
					(mid 108.449243 -215.607138)
					(end 108.521246 -215.535002)
				)
			)
		)
	)
	(zone
		(layers "F.Cu" "B.Cu" "In1.Cu" "In2.Cu" "In3.Cu" "In4.Cu" "In5.Cu" "In6.Cu"
			"In7.Cu" "In8.Cu" "In9.Cu" "In10.Cu" "In11.Cu" "In12.Cu" "In13.Cu" "In14.Cu"
			"In15.Cu" "In16.Cu"
		)
		(hatch none 0.5)
		(connect_pads
			(clearance 0)
		)
		(min_thickness 0.25)
		(keepout
			(tracks not_allowed)
			(vias allowed)
			(pads allowed)
			(copperpour not_allowed)
			(footprints allowed)
		)
		(placement
			(enabled no)
			(sheetname "")
		)
		(fill
			(thermal_gap 0.5)
			(thermal_bridge_width 0.5)
			(island_removal_mode 0)
		)
		(polygon
			(pts
				(arc
					(start 363.19841 -220.319854)
					(mid 362.54055 -220.319854)
					(end 363.19841 -220.319854)
				)
			)
		)
	)
	(zone
		(layers "F.Cu" "B.Cu" "In1.Cu" "In2.Cu" "In3.Cu" "In4.Cu" "In5.Cu" "In6.Cu"
			"In7.Cu" "In8.Cu" "In9.Cu" "In10.Cu" "In11.Cu" "In12.Cu" "In13.Cu" "In14.Cu"
			"In15.Cu" "In16.Cu"
		)
		(hatch none 0.5)
		(connect_pads
			(clearance 0)
		)
		(min_thickness 0.25)
		(keepout
			(tracks not_allowed)
			(vias allowed)
			(pads allowed)
			(copperpour not_allowed)
			(footprints allowed)
		)
		(placement
			(enabled no)
			(sheetname "")
		)
		(fill
			(thermal_gap 0.5)
			(thermal_bridge_width 0.5)
			(island_removal_mode 0)
		)
		(polygon
			(pts
				(arc
					(start 122.417078 -286.475424)
					(mid 121.759218 -286.475424)
					(end 122.417078 -286.475424)
				)
			)
		)
	)
	(zone
		(layers "F.Cu" "B.Cu" "In1.Cu" "In2.Cu" "In3.Cu" "In4.Cu" "In5.Cu" "In6.Cu"
			"In7.Cu" "In8.Cu" "In9.Cu" "In10.Cu" "In11.Cu" "In12.Cu" "In13.Cu" "In14.Cu"
			"In15.Cu" "In16.Cu"
		)
		(hatch none 0.5)
		(connect_pads
			(clearance 0)
		)
		(min_thickness 0.25)
		(keepout
			(tracks not_allowed)
			(vias allowed)
			(pads allowed)
			(copperpour not_allowed)
			(footprints allowed)
		)
		(placement
			(enabled no)
			(sheetname "")
		)
		(fill
			(thermal_gap 0.5)
			(thermal_bridge_width 0.5)
			(island_removal_mode 0)
		)
		(polygon
			(pts
				(arc
					(start 342.523064 -213.732618)
					(mid 341.865204 -213.732618)
					(end 342.523064 -213.732618)
				)
			)
		)
	)
	(zone
		(layers "F.Cu" "B.Cu" "In1.Cu" "In2.Cu" "In3.Cu" "In4.Cu" "In5.Cu" "In6.Cu"
			"In7.Cu" "In8.Cu" "In9.Cu" "In10.Cu" "In11.Cu" "In12.Cu" "In13.Cu" "In14.Cu"
			"In15.Cu" "In16.Cu"
		)
		(hatch none 0.5)
		(connect_pads
			(clearance 0)
		)
		(min_thickness 0.25)
		(keepout
			(tracks not_allowed)
			(vias allowed)
			(pads allowed)
			(copperpour not_allowed)
			(footprints allowed)
		)
		(placement
			(enabled no)
			(sheetname "")
		)
		(fill
			(thermal_gap 0.5)
			(thermal_bridge_width 0.5)
			(island_removal_mode 0)
		)
		(polygon
			(pts
				(arc
					(start 352.86061 -215.436704)
					(mid 352.20275 -215.436704)
					(end 352.86061 -215.436704)
				)
			)
		)
	)
	(zone
		(layers "F.Cu" "B.Cu" "In1.Cu" "In2.Cu" "In3.Cu" "In4.Cu" "In5.Cu" "In6.Cu"
			"In7.Cu" "In8.Cu" "In9.Cu" "In10.Cu" "In11.Cu" "In12.Cu" "In13.Cu" "In14.Cu"
			"In15.Cu" "In16.Cu"
		)
		(hatch none 0.5)
		(connect_pads
			(clearance 0)
		)
		(min_thickness 0.25)
		(keepout
			(tracks not_allowed)
			(vias allowed)
			(pads allowed)
			(copperpour not_allowed)
			(footprints allowed)
		)
		(placement
			(enabled no)
			(sheetname "")
		)
		(fill
			(thermal_gap 0.5)
			(thermal_bridge_width 0.5)
			(island_removal_mode 0)
		)
		(polygon
			(pts
				(arc
					(start 342.364314 -223.67367)
					(mid 342.383998 -223.62626)
					(end 342.39073 -223.575372)
				)
				(arc
					(start 342.39073 -223.575372)
					(mid 342.333074 -223.436178)
					(end 342.19388 -223.378522)
				)
				(arc
					(start 342.19388 -223.378522)
					(mid 342.095449 -223.404938)
					(end 342.023446 -223.477074)
				)
				(arc
					(start 341.5538 -224.291144)
					(mid 341.534116 -224.338554)
					(end 341.527384 -224.389442)
				)
				(arc
					(start 341.527384 -224.389442)
					(mid 341.58504 -224.528636)
					(end 341.724234 -224.586292)
				)
				(arc
					(start 341.724234 -224.586292)
					(mid 341.822665 -224.559876)
					(end 341.894668 -224.48774)
				)
			)
		)
	)
	(zone
		(layers "F.Cu" "B.Cu" "In1.Cu" "In2.Cu" "In3.Cu" "In4.Cu" "In5.Cu" "In6.Cu"
			"In7.Cu" "In8.Cu" "In9.Cu" "In10.Cu" "In11.Cu" "In12.Cu" "In13.Cu" "In14.Cu"
			"In15.Cu" "In16.Cu"
		)
		(hatch none 0.5)
		(connect_pads
			(clearance 0)
		)
		(min_thickness 0.25)
		(keepout
			(tracks not_allowed)
			(vias allowed)
			(pads allowed)
			(copperpour not_allowed)
			(footprints allowed)
		)
		(placement
			(enabled no)
			(sheetname "")
		)
		(fill
			(thermal_gap 0.5)
			(thermal_bridge_width 0.5)
			(island_removal_mode 0)
		)
		(polygon
			(pts
				(arc
					(start 357.871522 -217.780108)
					(mid 357.799533 -217.707949)
					(end 357.701088 -217.681556)
				)
				(arc
					(start 357.701088 -217.681556)
					(mid 357.561894 -217.739212)
					(end 357.504238 -217.878406)
				)
				(arc
					(start 357.504238 -217.878406)
					(mid 357.510995 -217.929287)
					(end 357.530654 -217.976704)
				)
				(arc
					(start 358.0003 -218.79052)
					(mid 358.072289 -218.862679)
					(end 358.170734 -218.889072)
				)
				(arc
					(start 358.170734 -218.889072)
					(mid 358.309928 -218.831416)
					(end 358.367584 -218.692222)
				)
				(arc
					(start 358.367584 -218.692222)
					(mid 358.360827 -218.641341)
					(end 358.341168 -218.593924)
				)
			)
		)
	)
	(zone
		(layers "F.Cu" "B.Cu" "In1.Cu" "In2.Cu" "In3.Cu" "In4.Cu" "In5.Cu" "In6.Cu"
			"In7.Cu" "In8.Cu" "In9.Cu" "In10.Cu" "In11.Cu" "In12.Cu" "In13.Cu" "In14.Cu"
			"In15.Cu" "In16.Cu"
		)
		(hatch none 0.5)
		(connect_pads
			(clearance 0)
		)
		(min_thickness 0.25)
		(keepout
			(tracks not_allowed)
			(vias allowed)
			(pads allowed)
			(copperpour not_allowed)
			(footprints allowed)
		)
		(placement
			(enabled no)
			(sheetname "")
		)
		(fill
			(thermal_gap 0.5)
			(thermal_bridge_width 0.5)
			(island_removal_mode 0)
		)
		(polygon
			(pts
				(arc
					(start 95.914464 -282.405836)
					(mid 96.572324 -282.405836)
					(end 95.914464 -282.405836)
				)
			)
		)
	)
	(zone
		(layers "F.Cu" "B.Cu" "In1.Cu" "In2.Cu" "In3.Cu" "In4.Cu" "In5.Cu" "In6.Cu"
			"In7.Cu" "In8.Cu" "In9.Cu" "In10.Cu" "In11.Cu" "In12.Cu" "In13.Cu" "In14.Cu"
			"In15.Cu" "In16.Cu"
		)
		(hatch none 0.5)
		(connect_pads
			(clearance 0)
		)
		(min_thickness 0.25)
		(keepout
			(tracks not_allowed)
			(vias allowed)
			(pads allowed)
			(copperpour not_allowed)
			(footprints allowed)
		)
		(placement
			(enabled no)
			(sheetname "")
		)
		(fill
			(thermal_gap 0.5)
			(thermal_bridge_width 0.5)
			(island_removal_mode 0)
		)
		(polygon
			(pts
				(arc
					(start 97.346262 -288.831274)
					(mid 97.278554 -288.759423)
					(end 97.183448 -288.732976)
				)
				(arc
					(start 97.183448 -288.732976)
					(mid 97.053234 -288.786912)
					(end 96.999298 -288.917126)
				)
				(arc
					(start 96.999298 -288.917126)
					(mid 97.004749 -288.961347)
					(end 97.020634 -289.002978)
				)
				(arc
					(start 97.49028 -289.892994)
					(mid 97.557988 -289.964845)
					(end 97.653094 -289.991292)
				)
				(arc
					(start 97.653094 -289.991292)
					(mid 97.783308 -289.937356)
					(end 97.837244 -289.807142)
				)
				(arc
					(start 97.837244 -289.807142)
					(mid 97.831793 -289.762921)
					(end 97.815908 -289.72129)
				)
			)
		)
	)
	(zone
		(layers "F.Cu" "B.Cu" "In1.Cu" "In2.Cu" "In3.Cu" "In4.Cu" "In5.Cu" "In6.Cu"
			"In7.Cu" "In8.Cu" "In9.Cu" "In10.Cu" "In11.Cu" "In12.Cu" "In13.Cu" "In14.Cu"
			"In15.Cu" "In16.Cu"
		)
		(hatch none 0.5)
		(connect_pads
			(clearance 0)
		)
		(min_thickness 0.25)
		(keepout
			(tracks not_allowed)
			(vias allowed)
			(pads allowed)
			(copperpour not_allowed)
			(footprints allowed)
		)
		(placement
			(enabled no)
			(sheetname "")
		)
		(fill
			(thermal_gap 0.5)
			(thermal_bridge_width 0.5)
			(island_removal_mode 0)
		)
		(polygon
			(pts
				(arc
					(start 155.196794 -406.62352)
					(mid 154.815794 -407.00452)
					(end 155.196794 -407.38552)
				)
				(arc
					(start 156.060394 -407.38552)
					(mid 156.441394 -407.00452)
					(end 156.060394 -406.62352)
				)
			)
		)
	)
	(zone
		(layers "F.Cu" "B.Cu" "In1.Cu" "In2.Cu" "In3.Cu" "In4.Cu" "In5.Cu" "In6.Cu"
			"In7.Cu" "In8.Cu" "In9.Cu" "In10.Cu" "In11.Cu" "In12.Cu" "In13.Cu" "In14.Cu"
			"In15.Cu" "In16.Cu"
		)
		(hatch none 0.5)
		(connect_pads
			(clearance 0)
		)
		(min_thickness 0.25)
		(keepout
			(tracks not_allowed)
			(vias allowed)
			(pads allowed)
			(copperpour not_allowed)
			(footprints allowed)
		)
		(placement
			(enabled no)
			(sheetname "")
		)
		(fill
			(thermal_gap 0.5)
			(thermal_bridge_width 0.5)
			(island_removal_mode 0)
		)
		(polygon
			(pts
				(arc
					(start 353.440746 -276.708616)
					(mid 352.782886 -276.708616)
					(end 353.440746 -276.708616)
				)
			)
		)
	)
	(zone
		(layers "F.Cu" "B.Cu" "In1.Cu" "In2.Cu" "In3.Cu" "In4.Cu" "In5.Cu" "In6.Cu"
			"In7.Cu" "In8.Cu" "In9.Cu" "In10.Cu" "In11.Cu" "In12.Cu" "In13.Cu" "In14.Cu"
			"In15.Cu" "In16.Cu"
		)
		(hatch none 0.5)
		(connect_pads
			(clearance 0)
		)
		(min_thickness 0.25)
		(keepout
			(tracks not_allowed)
			(vias allowed)
			(pads allowed)
			(copperpour not_allowed)
			(footprints allowed)
		)
		(placement
			(enabled no)
			(sheetname "")
		)
		(fill
			(thermal_gap 0.5)
			(thermal_bridge_width 0.5)
			(island_removal_mode 0)
		)
		(polygon
			(pts
				(arc
					(start 123.246388 -214.622634)
					(mid 122.588528 -214.622634)
					(end 123.246388 -214.622634)
				)
			)
		)
	)
	(zone
		(layers "F.Cu" "B.Cu" "In1.Cu" "In2.Cu" "In3.Cu" "In4.Cu" "In5.Cu" "In6.Cu"
			"In7.Cu" "In8.Cu" "In9.Cu" "In10.Cu" "In11.Cu" "In12.Cu" "In13.Cu" "In14.Cu"
			"In15.Cu" "In16.Cu"
		)
		(hatch none 0.5)
		(connect_pads
			(clearance 0)
		)
		(min_thickness 0.25)
		(keepout
			(tracks not_allowed)
			(vias allowed)
			(pads allowed)
			(copperpour not_allowed)
			(footprints allowed)
		)
		(placement
			(enabled no)
			(sheetname "")
		)
		(fill
			(thermal_gap 0.5)
			(thermal_bridge_width 0.5)
			(island_removal_mode 0)
		)
		(polygon
			(pts
				(arc
					(start 351.762314 -223.67367)
					(mid 351.781998 -223.62626)
					(end 351.78873 -223.575372)
				)
				(arc
					(start 351.78873 -223.575372)
					(mid 351.731074 -223.436178)
					(end 351.59188 -223.378522)
				)
				(arc
					(start 351.59188 -223.378522)
					(mid 351.493449 -223.404938)
					(end 351.421446 -223.477074)
				)
				(arc
					(start 350.9518 -224.291144)
					(mid 350.932116 -224.338554)
					(end 350.925384 -224.389442)
				)
				(arc
					(start 350.925384 -224.389442)
					(mid 350.98304 -224.528636)
					(end 351.122234 -224.586292)
				)
				(arc
					(start 351.122234 -224.586292)
					(mid 351.220665 -224.559876)
					(end 351.292668 -224.48774)
				)
			)
		)
	)
	(zone
		(layers "F.Cu" "B.Cu" "In1.Cu" "In2.Cu" "In3.Cu" "In4.Cu" "In5.Cu" "In6.Cu"
			"In7.Cu" "In8.Cu" "In9.Cu" "In10.Cu" "In11.Cu" "In12.Cu" "In13.Cu" "In14.Cu"
			"In15.Cu" "In16.Cu"
		)
		(hatch none 0.5)
		(connect_pads
			(clearance 0)
		)
		(min_thickness 0.25)
		(keepout
			(tracks not_allowed)
			(vias allowed)
			(pads allowed)
			(copperpour not_allowed)
			(footprints allowed)
		)
		(placement
			(enabled no)
			(sheetname "")
		)
		(fill
			(thermal_gap 0.5)
			(thermal_bridge_width 0.5)
			(island_removal_mode 0)
		)
		(polygon
			(pts
				(arc
					(start 376.825764 -224.389442)
					(mid 376.167904 -224.389442)
					(end 376.825764 -224.389442)
				)
			)
		)
	)
	(zone
		(layers "F.Cu" "B.Cu" "In1.Cu" "In2.Cu" "In3.Cu" "In4.Cu" "In5.Cu" "In6.Cu"
			"In7.Cu" "In8.Cu" "In9.Cu" "In10.Cu" "In11.Cu" "In12.Cu" "In13.Cu" "In14.Cu"
			"In15.Cu" "In16.Cu"
		)
		(hatch none 0.5)
		(connect_pads
			(clearance 0)
		)
		(min_thickness 0.25)
		(keepout
			(tracks not_allowed)
			(vias allowed)
			(pads allowed)
			(copperpour not_allowed)
			(footprints allowed)
		)
		(placement
			(enabled no)
			(sheetname "")
		)
		(fill
			(thermal_gap 0.5)
			(thermal_bridge_width 0.5)
			(island_removal_mode 0)
		)
		(polygon
			(pts
				(arc
					(start 125.988064 -285.661354)
					(mid 126.645924 -285.661354)
					(end 125.988064 -285.661354)
				)
			)
		)
	)
	(zone
		(layers "F.Cu" "B.Cu" "In1.Cu" "In2.Cu" "In3.Cu" "In4.Cu" "In5.Cu" "In6.Cu"
			"In7.Cu" "In8.Cu" "In9.Cu" "In10.Cu" "In11.Cu" "In12.Cu" "In13.Cu" "In14.Cu"
			"In15.Cu" "In16.Cu"
		)
		(hatch none 0.5)
		(connect_pads
			(clearance 0)
		)
		(min_thickness 0.25)
		(keepout
			(tracks not_allowed)
			(vias allowed)
			(pads allowed)
			(copperpour not_allowed)
			(footprints allowed)
		)
		(placement
			(enabled no)
			(sheetname "")
		)
		(fill
			(thermal_gap 0.5)
			(thermal_bridge_width 0.5)
			(island_removal_mode 0)
		)
		(polygon
			(pts
				(arc
					(start 347.691964 -224.389442)
					(mid 347.034104 -224.389442)
					(end 347.691964 -224.389442)
				)
			)
		)
	)
	(zone
		(layers "F.Cu" "B.Cu" "In1.Cu" "In2.Cu" "In3.Cu" "In4.Cu" "In5.Cu" "In6.Cu"
			"In7.Cu" "In8.Cu" "In9.Cu" "In10.Cu" "In11.Cu" "In12.Cu" "In13.Cu" "In14.Cu"
			"In15.Cu" "In16.Cu"
		)
		(hatch none 0.5)
		(connect_pads
			(clearance 0)
		)
		(min_thickness 0.25)
		(keepout
			(tracks not_allowed)
			(vias allowed)
			(pads allowed)
			(copperpour not_allowed)
			(footprints allowed)
		)
		(placement
			(enabled no)
			(sheetname "")
		)
		(fill
			(thermal_gap 0.5)
			(thermal_bridge_width 0.5)
			(island_removal_mode 0)
		)
		(polygon
			(pts
				(arc
					(start 337.518756 -74.944224)
					(mid 337.899756 -74.563224)
					(end 337.518756 -74.182224)
				)
				(arc
					(start 336.655156 -74.182224)
					(mid 336.274156 -74.563224)
					(end 336.655156 -74.944224)
				)
			)
		)
	)
	(zone
		(layers "F.Cu" "B.Cu" "In1.Cu" "In2.Cu" "In3.Cu" "In4.Cu" "In5.Cu" "In6.Cu"
			"In7.Cu" "In8.Cu" "In9.Cu" "In10.Cu" "In11.Cu" "In12.Cu" "In13.Cu" "In14.Cu"
			"In15.Cu" "In16.Cu"
		)
		(hatch none 0.5)
		(connect_pads
			(clearance 0)
		)
		(min_thickness 0.25)
		(keepout
			(tracks not_allowed)
			(vias allowed)
			(pads allowed)
			(copperpour not_allowed)
			(footprints allowed)
		)
		(placement
			(enabled no)
			(sheetname "")
		)
		(fill
			(thermal_gap 0.5)
			(thermal_bridge_width 0.5)
			(island_removal_mode 0)
		)
		(polygon
			(pts
				(arc
					(start 354.850192 -277.522432)
					(mid 354.192332 -277.522432)
					(end 354.850192 -277.522432)
				)
			)
		)
	)
	(zone
		(layers "F.Cu" "B.Cu" "In1.Cu" "In2.Cu" "In3.Cu" "In4.Cu" "In5.Cu" "In6.Cu"
			"In7.Cu" "In8.Cu" "In9.Cu" "In10.Cu" "In11.Cu" "In12.Cu" "In13.Cu" "In14.Cu"
			"In15.Cu" "In16.Cu"
		)
		(hatch none 0.5)
		(connect_pads
			(clearance 0)
		)
		(min_thickness 0.25)
		(keepout
			(tracks not_allowed)
			(vias allowed)
			(pads allowed)
			(copperpour not_allowed)
			(footprints allowed)
		)
		(placement
			(enabled no)
			(sheetname "")
		)
		(fill
			(thermal_gap 0.5)
			(thermal_bridge_width 0.5)
			(island_removal_mode 0)
		)
		(polygon
			(pts
				(arc
					(start 383.582926 -297.515026)
					(mid 379.13691 -297.515026)
					(end 383.582926 -297.515026)
				)
			)
		)
	)
	(zone
		(layers "F.Cu" "B.Cu" "In1.Cu" "In2.Cu" "In3.Cu" "In4.Cu" "In5.Cu" "In6.Cu"
			"In7.Cu" "In8.Cu" "In9.Cu" "In10.Cu" "In11.Cu" "In12.Cu" "In13.Cu" "In14.Cu"
			"In15.Cu" "In16.Cu"
		)
		(hatch none 0.5)
		(connect_pads
			(clearance 0)
		)
		(min_thickness 0.25)
		(keepout
			(tracks not_allowed)
			(vias allowed)
			(pads allowed)
			(copperpour not_allowed)
			(footprints allowed)
		)
		(placement
			(enabled no)
			(sheetname "")
		)
		(fill
			(thermal_gap 0.5)
			(thermal_bridge_width 0.5)
			(island_removal_mode 0)
		)
		(polygon
			(pts
				(arc
					(start 122.229118 -288.917126)
					(mid 122.886978 -288.917126)
					(end 122.229118 -288.917126)
				)
			)
		)
	)
	(zone
		(layers "F.Cu" "B.Cu" "In1.Cu" "In2.Cu" "In3.Cu" "In4.Cu" "In5.Cu" "In6.Cu"
			"In7.Cu" "In8.Cu" "In9.Cu" "In10.Cu" "In11.Cu" "In12.Cu" "In13.Cu" "In14.Cu"
			"In15.Cu" "In16.Cu"
		)
		(hatch none 0.5)
		(connect_pads
			(clearance 0)
		)
		(min_thickness 0.25)
		(keepout
			(tracks not_allowed)
			(vias allowed)
			(pads allowed)
			(copperpour not_allowed)
			(footprints allowed)
		)
		(placement
			(enabled no)
			(sheetname "")
		)
		(fill
			(thermal_gap 0.5)
			(thermal_bridge_width 0.5)
			(island_removal_mode 0)
		)
		(polygon
			(pts
				(arc
					(start 95.474282 -285.563056)
					(mid 95.402293 -285.490897)
					(end 95.303848 -285.464504)
				)
				(arc
					(start 95.303848 -285.464504)
					(mid 95.164654 -285.52216)
					(end 95.106998 -285.661354)
				)
				(arc
					(start 95.106998 -285.661354)
					(mid 95.113755 -285.712235)
					(end 95.133414 -285.759652)
				)
				(arc
					(start 95.603314 -286.573722)
					(mid 95.675303 -286.645881)
					(end 95.773748 -286.672274)
				)
				(arc
					(start 95.773748 -286.672274)
					(mid 95.912942 -286.614618)
					(end 95.970598 -286.475424)
				)
				(arc
					(start 95.970598 -286.475424)
					(mid 95.963841 -286.424543)
					(end 95.944182 -286.377126)
				)
			)
		)
	)
	(zone
		(layers "F.Cu" "B.Cu" "In1.Cu" "In2.Cu" "In3.Cu" "In4.Cu" "In5.Cu" "In6.Cu"
			"In7.Cu" "In8.Cu" "In9.Cu" "In10.Cu" "In11.Cu" "In12.Cu" "In13.Cu" "In14.Cu"
			"In15.Cu" "In16.Cu"
		)
		(hatch none 0.5)
		(connect_pads
			(clearance 0)
		)
		(min_thickness 0.25)
		(keepout
			(tracks not_allowed)
			(vias allowed)
			(pads allowed)
			(copperpour not_allowed)
			(footprints allowed)
		)
		(placement
			(enabled no)
			(sheetname "")
		)
		(fill
			(thermal_gap 0.5)
			(thermal_bridge_width 0.5)
			(island_removal_mode 0)
		)
		(polygon
			(pts
				(arc
					(start 108.679742 -218.692222)
					(mid 108.021882 -218.692222)
					(end 108.679742 -218.692222)
				)
			)
		)
	)
	(zone
		(layers "F.Cu" "B.Cu" "In1.Cu" "In2.Cu" "In3.Cu" "In4.Cu" "In5.Cu" "In6.Cu"
			"In7.Cu" "In8.Cu" "In9.Cu" "In10.Cu" "In11.Cu" "In12.Cu" "In13.Cu" "In14.Cu"
			"In15.Cu" "In16.Cu"
		)
		(hatch none 0.5)
		(connect_pads
			(clearance 0)
		)
		(min_thickness 0.25)
		(keepout
			(tracks not_allowed)
			(vias allowed)
			(pads allowed)
			(copperpour not_allowed)
			(footprints allowed)
		)
		(placement
			(enabled no)
			(sheetname "")
		)
		(fill
			(thermal_gap 0.5)
			(thermal_bridge_width 0.5)
			(island_removal_mode 0)
		)
		(polygon
			(pts
				(arc
					(start 377.765564 -224.389442)
					(mid 377.107704 -224.389442)
					(end 377.765564 -224.389442)
				)
			)
		)
	)
	(zone
		(layers "F.Cu" "B.Cu" "In1.Cu" "In2.Cu" "In3.Cu" "In4.Cu" "In5.Cu" "In6.Cu"
			"In7.Cu" "In8.Cu" "In9.Cu" "In10.Cu" "In11.Cu" "In12.Cu" "In13.Cu" "In14.Cu"
			"In15.Cu" "In16.Cu"
		)
		(hatch none 0.5)
		(connect_pads
			(clearance 0)
		)
		(min_thickness 0.25)
		(keepout
			(tracks not_allowed)
			(vias allowed)
			(pads allowed)
			(copperpour not_allowed)
			(footprints allowed)
		)
		(placement
			(enabled no)
			(sheetname "")
		)
		(fill
			(thermal_gap 0.5)
			(thermal_bridge_width 0.5)
			(island_removal_mode 0)
		)
		(polygon
			(pts
				(arc
					(start 376.825764 -217.878406)
					(mid 376.167904 -217.878406)
					(end 376.825764 -217.878406)
				)
			)
		)
	)
	(zone
		(layers "F.Cu" "B.Cu" "In1.Cu" "In2.Cu" "In3.Cu" "In4.Cu" "In5.Cu" "In6.Cu"
			"In7.Cu" "In8.Cu" "In9.Cu" "In10.Cu" "In11.Cu" "In12.Cu" "In13.Cu" "In14.Cu"
			"In15.Cu" "In16.Cu"
		)
		(hatch none 0.5)
		(connect_pads
			(clearance 0)
		)
		(min_thickness 0.25)
		(keepout
			(tracks not_allowed)
			(vias allowed)
			(pads allowed)
			(copperpour not_allowed)
			(footprints allowed)
		)
		(placement
			(enabled no)
			(sheetname "")
		)
		(fill
			(thermal_gap 0.5)
			(thermal_bridge_width 0.5)
			(island_removal_mode 0)
		)
		(polygon
			(pts
				(arc
					(start 356.93096 -214.720932)
					(mid 356.950644 -214.673522)
					(end 356.957376 -214.622634)
				)
				(arc
					(start 356.957376 -214.622634)
					(mid 356.89972 -214.48344)
					(end 356.760526 -214.425784)
				)
				(arc
					(start 356.760526 -214.425784)
					(mid 356.662095 -214.4522)
					(end 356.590092 -214.524336)
				)
				(arc
					(start 356.120446 -215.338406)
					(mid 356.100762 -215.385816)
					(end 356.09403 -215.436704)
				)
				(arc
					(start 356.09403 -215.436704)
					(mid 356.151686 -215.575898)
					(end 356.29088 -215.633554)
				)
				(arc
					(start 356.29088 -215.633554)
					(mid 356.389311 -215.607138)
					(end 356.461314 -215.535002)
				)
			)
		)
	)
	(zone
		(layers "F.Cu" "B.Cu" "In1.Cu" "In2.Cu" "In3.Cu" "In4.Cu" "In5.Cu" "In6.Cu"
			"In7.Cu" "In8.Cu" "In9.Cu" "In10.Cu" "In11.Cu" "In12.Cu" "In13.Cu" "In14.Cu"
			"In15.Cu" "In16.Cu"
		)
		(hatch none 0.5)
		(connect_pads
			(clearance 0)
		)
		(min_thickness 0.25)
		(keepout
			(tracks not_allowed)
			(vias allowed)
			(pads allowed)
			(copperpour not_allowed)
			(footprints allowed)
		)
		(placement
			(enabled no)
			(sheetname "")
		)
		(fill
			(thermal_gap 0.5)
			(thermal_bridge_width 0.5)
			(island_removal_mode 0)
		)
		(polygon
			(pts
				(arc
					(start 364.13821 -225.203258)
					(mid 363.48035 -225.203258)
					(end 364.13821 -225.203258)
				)
			)
		)
	)
	(zone
		(layers "F.Cu" "B.Cu" "In1.Cu" "In2.Cu" "In3.Cu" "In4.Cu" "In5.Cu" "In6.Cu"
			"In7.Cu" "In8.Cu" "In9.Cu" "In10.Cu" "In11.Cu" "In12.Cu" "In13.Cu" "In14.Cu"
			"In15.Cu" "In16.Cu"
		)
		(hatch none 0.5)
		(connect_pads
			(clearance 0)
		)
		(min_thickness 0.25)
		(keepout
			(tracks not_allowed)
			(vias allowed)
			(pads allowed)
			(copperpour not_allowed)
			(footprints allowed)
		)
		(placement
			(enabled no)
			(sheetname "")
		)
		(fill
			(thermal_gap 0.5)
			(thermal_bridge_width 0.5)
			(island_removal_mode 0)
		)
		(polygon
			(pts
				(arc
					(start 92.53728 -213.646766)
					(mid 92.469572 -213.574915)
					(end 92.374466 -213.548468)
				)
				(arc
					(start 92.374466 -213.548468)
					(mid 92.244252 -213.602404)
					(end 92.190316 -213.732618)
				)
				(arc
					(start 92.190316 -213.732618)
					(mid 92.195767 -213.776839)
					(end 92.211652 -213.81847)
				)
				(arc
					(start 92.681044 -214.708486)
					(mid 92.748752 -214.780337)
					(end 92.843858 -214.806784)
				)
				(arc
					(start 92.843858 -214.806784)
					(mid 92.974072 -214.752848)
					(end 93.028008 -214.622634)
				)
				(arc
					(start 93.028008 -214.622634)
					(mid 93.022557 -214.578413)
					(end 93.006672 -214.536782)
				)
			)
		)
	)
	(zone
		(layers "F.Cu" "B.Cu" "In1.Cu" "In2.Cu" "In3.Cu" "In4.Cu" "In5.Cu" "In6.Cu"
			"In7.Cu" "In8.Cu" "In9.Cu" "In10.Cu" "In11.Cu" "In12.Cu" "In13.Cu" "In14.Cu"
			"In15.Cu" "In16.Cu"
		)
		(hatch none 0.5)
		(connect_pads
			(clearance 0)
		)
		(min_thickness 0.25)
		(keepout
			(tracks not_allowed)
			(vias allowed)
			(pads allowed)
			(copperpour not_allowed)
			(footprints allowed)
		)
		(placement
			(enabled no)
			(sheetname "")
		)
		(fill
			(thermal_gap 0.5)
			(thermal_bridge_width 0.5)
			(island_removal_mode 0)
		)
		(polygon
			(pts
				(arc
					(start 348.631256 -214.622634)
					(mid 347.973396 -214.622634)
					(end 348.631256 -214.622634)
				)
			)
		)
	)
	(zone
		(layers "F.Cu" "B.Cu" "In1.Cu" "In2.Cu" "In3.Cu" "In4.Cu" "In5.Cu" "In6.Cu"
			"In7.Cu" "In8.Cu" "In9.Cu" "In10.Cu" "In11.Cu" "In12.Cu" "In13.Cu" "In14.Cu"
			"In15.Cu" "In16.Cu"
		)
		(hatch none 0.5)
		(connect_pads
			(clearance 0)
		)
		(min_thickness 0.25)
		(keepout
			(tracks not_allowed)
			(vias allowed)
			(pads allowed)
			(copperpour not_allowed)
			(footprints allowed)
		)
		(placement
			(enabled no)
			(sheetname "")
		)
		(fill
			(thermal_gap 0.5)
			(thermal_bridge_width 0.5)
			(island_removal_mode 0)
		)
		(polygon
			(pts
				(arc
					(start 70.768718 -406.62352)
					(mid 70.387718 -407.00452)
					(end 70.768718 -407.38552)
				)
				(arc
					(start 71.632318 -407.38552)
					(mid 72.013318 -407.00452)
					(end 71.632318 -406.62352)
				)
			)
		)
	)
	(zone
		(layers "F.Cu" "B.Cu" "In1.Cu" "In2.Cu" "In3.Cu" "In4.Cu" "In5.Cu" "In6.Cu"
			"In7.Cu" "In8.Cu" "In9.Cu" "In10.Cu" "In11.Cu" "In12.Cu" "In13.Cu" "In14.Cu"
			"In15.Cu" "In16.Cu"
		)
		(hatch none 0.5)
		(connect_pads
			(clearance 0)
		)
		(min_thickness 0.25)
		(keepout
			(tracks not_allowed)
			(vias allowed)
			(pads allowed)
			(copperpour not_allowed)
			(footprints allowed)
		)
		(placement
			(enabled no)
			(sheetname "")
		)
		(fill
			(thermal_gap 0.5)
			(thermal_bridge_width 0.5)
			(island_removal_mode 0)
		)
		(polygon
			(pts
				(arc
					(start 353.440746 -275.08073)
					(mid 352.782886 -275.08073)
					(end 353.440746 -275.08073)
				)
			)
		)
	)
	(zone
		(layers "F.Cu" "B.Cu" "In1.Cu" "In2.Cu" "In3.Cu" "In4.Cu" "In5.Cu" "In6.Cu"
			"In7.Cu" "In8.Cu" "In9.Cu" "In10.Cu" "In11.Cu" "In12.Cu" "In13.Cu" "In14.Cu"
			"In15.Cu" "In16.Cu"
		)
		(hatch none 0.5)
		(connect_pads
			(clearance 0)
		)
		(min_thickness 0.25)
		(keepout
			(tracks not_allowed)
			(vias allowed)
			(pads allowed)
			(copperpour not_allowed)
			(footprints allowed)
		)
		(placement
			(enabled no)
			(sheetname "")
		)
		(fill
			(thermal_gap 0.5)
			(thermal_bridge_width 0.5)
			(island_removal_mode 0)
		)
		(polygon
			(pts
				(arc
					(start 353.642422 -220.22181)
					(mid 353.570433 -220.149651)
					(end 353.471988 -220.123258)
				)
				(arc
					(start 353.471988 -220.123258)
					(mid 353.332794 -220.180914)
					(end 353.275138 -220.320108)
				)
				(arc
					(start 353.275138 -220.320108)
					(mid 353.281895 -220.370989)
					(end 353.301554 -220.418406)
				)
				(arc
					(start 353.7712 -221.232222)
					(mid 353.843189 -221.304381)
					(end 353.941634 -221.330774)
				)
				(arc
					(start 353.941634 -221.330774)
					(mid 354.080828 -221.273118)
					(end 354.138484 -221.133924)
				)
				(arc
					(start 354.138484 -221.133924)
					(mid 354.131727 -221.083043)
					(end 354.112068 -221.035626)
				)
			)
		)
	)
	(zone
		(layers "F.Cu" "B.Cu" "In1.Cu" "In2.Cu" "In3.Cu" "In4.Cu" "In5.Cu" "In6.Cu"
			"In7.Cu" "In8.Cu" "In9.Cu" "In10.Cu" "In11.Cu" "In12.Cu" "In13.Cu" "In14.Cu"
			"In15.Cu" "In16.Cu"
		)
		(hatch none 0.5)
		(connect_pads
			(clearance 0)
		)
		(min_thickness 0.25)
		(keepout
			(tracks not_allowed)
			(vias allowed)
			(pads allowed)
			(copperpour not_allowed)
			(footprints allowed)
		)
		(placement
			(enabled no)
			(sheetname "")
		)
		(fill
			(thermal_gap 0.5)
			(thermal_bridge_width 0.5)
			(island_removal_mode 0)
		)
		(polygon
			(pts
				(arc
					(start 336.725514 -215.338406)
					(mid 336.653525 -215.266247)
					(end 336.55508 -215.239854)
				)
				(arc
					(start 336.55508 -215.239854)
					(mid 336.415886 -215.29751)
					(end 336.35823 -215.436704)
				)
				(arc
					(start 336.35823 -215.436704)
					(mid 336.364987 -215.487585)
					(end 336.384646 -215.535002)
				)
				(arc
					(start 336.854292 -216.348818)
					(mid 336.926281 -216.420977)
					(end 337.024726 -216.44737)
				)
				(arc
					(start 337.024726 -216.44737)
					(mid 337.16392 -216.389714)
					(end 337.221576 -216.25052)
				)
				(arc
					(start 337.221576 -216.25052)
					(mid 337.214819 -216.199639)
					(end 337.19516 -216.152222)
				)
			)
		)
	)
	(zone
		(layers "F.Cu" "B.Cu" "In1.Cu" "In2.Cu" "In3.Cu" "In4.Cu" "In5.Cu" "In6.Cu"
			"In7.Cu" "In8.Cu" "In9.Cu" "In10.Cu" "In11.Cu" "In12.Cu" "In13.Cu" "In14.Cu"
			"In15.Cu" "In16.Cu"
		)
		(hatch none 0.5)
		(connect_pads
			(clearance 0)
		)
		(min_thickness 0.25)
		(keepout
			(tracks not_allowed)
			(vias allowed)
			(pads allowed)
			(copperpour not_allowed)
			(footprints allowed)
		)
		(placement
			(enabled no)
			(sheetname "")
		)
		(fill
			(thermal_gap 0.5)
			(thermal_bridge_width 0.5)
			(island_removal_mode 0)
		)
		(polygon
			(pts
				(arc
					(start 95.162878 -284.847538)
					(mid 94.505018 -284.847538)
					(end 95.162878 -284.847538)
				)
			)
		)
	)
	(zone
		(layers "F.Cu" "B.Cu" "In1.Cu" "In2.Cu" "In3.Cu" "In4.Cu" "In5.Cu" "In6.Cu"
			"In7.Cu" "In8.Cu" "In9.Cu" "In10.Cu" "In11.Cu" "In12.Cu" "In13.Cu" "In14.Cu"
			"In15.Cu" "In16.Cu"
		)
		(hatch none 0.5)
		(connect_pads
			(clearance 0)
		)
		(min_thickness 0.25)
		(keepout
			(tracks not_allowed)
			(vias allowed)
			(pads allowed)
			(copperpour not_allowed)
			(footprints allowed)
		)
		(placement
			(enabled no)
			(sheetname "")
		)
		(fill
			(thermal_gap 0.5)
			(thermal_bridge_width 0.5)
			(island_removal_mode 0)
		)
		(polygon
			(pts
				(arc
					(start 149.070314 -406.62352)
					(mid 148.689314 -407.00452)
					(end 149.070314 -407.38552)
				)
				(arc
					(start 149.933914 -407.38552)
					(mid 150.314914 -407.00452)
					(end 149.933914 -406.62352)
				)
			)
		)
	)
	(zone
		(layers "F.Cu" "B.Cu" "In1.Cu" "In2.Cu" "In3.Cu" "In4.Cu" "In5.Cu" "In6.Cu"
			"In7.Cu" "In8.Cu" "In9.Cu" "In10.Cu" "In11.Cu" "In12.Cu" "In13.Cu" "In14.Cu"
			"In15.Cu" "In16.Cu"
		)
		(hatch none 0.5)
		(connect_pads
			(clearance 0)
		)
		(min_thickness 0.25)
		(keepout
			(tracks not_allowed)
			(vias allowed)
			(pads allowed)
			(copperpour not_allowed)
			(footprints allowed)
		)
		(placement
			(enabled no)
			(sheetname "")
		)
		(fill
			(thermal_gap 0.5)
			(thermal_bridge_width 0.5)
			(island_removal_mode 0)
		)
		(polygon
			(pts
				(arc
					(start 348.271846 -288.917126)
					(mid 347.613986 -288.917126)
					(end 348.271846 -288.917126)
				)
			)
		)
	)
	(zone
		(layers "F.Cu" "B.Cu" "In1.Cu" "In2.Cu" "In3.Cu" "In4.Cu" "In5.Cu" "In6.Cu"
			"In7.Cu" "In8.Cu" "In9.Cu" "In10.Cu" "In11.Cu" "In12.Cu" "In13.Cu" "In14.Cu"
			"In15.Cu" "In16.Cu"
		)
		(hatch none 0.5)
		(connect_pads
			(clearance 0)
		)
		(min_thickness 0.25)
		(keepout
			(tracks not_allowed)
			(vias allowed)
			(pads allowed)
			(copperpour not_allowed)
			(footprints allowed)
		)
		(placement
			(enabled no)
			(sheetname "")
		)
		(fill
			(thermal_gap 0.5)
			(thermal_bridge_width 0.5)
			(island_removal_mode 0)
		)
		(polygon
			(pts
				(xy 470.499948 -320.71183) (xy 470.499948 -315.71184) (xy 470.804748 -316.01664) (xy 470.804748 -320.40703)
			)
		)
	)
	(zone
		(layers "F.Cu" "B.Cu" "In1.Cu" "In2.Cu" "In3.Cu" "In4.Cu" "In5.Cu" "In6.Cu"
			"In7.Cu" "In8.Cu" "In9.Cu" "In10.Cu" "In11.Cu" "In12.Cu" "In13.Cu" "In14.Cu"
			"In15.Cu" "In16.Cu"
		)
		(hatch none 0.5)
		(connect_pads
			(clearance 0)
		)
		(min_thickness 0.25)
		(keepout
			(tracks not_allowed)
			(vias allowed)
			(pads allowed)
			(copperpour not_allowed)
			(footprints allowed)
		)
		(placement
			(enabled no)
			(sheetname "")
		)
		(fill
			(thermal_gap 0.5)
			(thermal_bridge_width 0.5)
			(island_removal_mode 0)
		)
		(polygon
			(pts
				(arc
					(start 111.499396 -217.064336)
					(mid 110.841536 -217.064336)
					(end 111.499396 -217.064336)
				)
			)
		)
	)
	(zone
		(layers "F.Cu" "B.Cu" "In1.Cu" "In2.Cu" "In3.Cu" "In4.Cu" "In5.Cu" "In6.Cu"
			"In7.Cu" "In8.Cu" "In9.Cu" "In10.Cu" "In11.Cu" "In12.Cu" "In13.Cu" "In14.Cu"
			"In15.Cu" "In16.Cu"
		)
		(hatch none 0.5)
		(connect_pads
			(clearance 0)
		)
		(min_thickness 0.25)
		(keepout
			(tracks not_allowed)
			(vias allowed)
			(pads allowed)
			(copperpour not_allowed)
			(footprints allowed)
		)
		(placement
			(enabled no)
			(sheetname "")
		)
		(fill
			(thermal_gap 0.5)
			(thermal_bridge_width 0.5)
			(island_removal_mode 0)
		)
		(polygon
			(pts
				(arc
					(start 346.862146 -288.103056)
					(mid 346.204286 -288.103056)
					(end 346.862146 -288.103056)
				)
			)
		)
	)
	(zone
		(layers "F.Cu" "B.Cu" "In1.Cu" "In2.Cu" "In3.Cu" "In4.Cu" "In5.Cu" "In6.Cu"
			"In7.Cu" "In8.Cu" "In9.Cu" "In10.Cu" "In11.Cu" "In12.Cu" "In13.Cu" "In14.Cu"
			"In15.Cu" "In16.Cu"
		)
		(hatch none 0.5)
		(connect_pads
			(clearance 0)
		)
		(min_thickness 0.25)
		(keepout
			(tracks not_allowed)
			(vias allowed)
			(pads allowed)
			(copperpour not_allowed)
			(footprints allowed)
		)
		(placement
			(enabled no)
			(sheetname "")
		)
		(fill
			(thermal_gap 0.5)
			(thermal_bridge_width 0.5)
			(island_removal_mode 0)
		)
		(polygon
			(pts
				(arc
					(start 100.05568 -213.646766)
					(mid 99.987972 -213.574915)
					(end 99.892866 -213.548468)
				)
				(arc
					(start 99.892866 -213.548468)
					(mid 99.762652 -213.602404)
					(end 99.708716 -213.732618)
				)
				(arc
					(start 99.708716 -213.732618)
					(mid 99.714167 -213.776839)
					(end 99.730052 -213.81847)
				)
				(arc
					(start 100.199444 -214.708486)
					(mid 100.267152 -214.780337)
					(end 100.362258 -214.806784)
				)
				(arc
					(start 100.362258 -214.806784)
					(mid 100.492472 -214.752848)
					(end 100.546408 -214.622634)
				)
				(arc
					(start 100.546408 -214.622634)
					(mid 100.540957 -214.578413)
					(end 100.525072 -214.536782)
				)
			)
		)
	)
	(zone
		(layers "F.Cu" "B.Cu" "In1.Cu" "In2.Cu" "In3.Cu" "In4.Cu" "In5.Cu" "In6.Cu"
			"In7.Cu" "In8.Cu" "In9.Cu" "In10.Cu" "In11.Cu" "In12.Cu" "In13.Cu" "In14.Cu"
			"In15.Cu" "In16.Cu"
		)
		(hatch none 0.5)
		(connect_pads
			(clearance 0)
		)
		(min_thickness 0.25)
		(keepout
			(tracks not_allowed)
			(vias allowed)
			(pads allowed)
			(copperpour not_allowed)
			(footprints allowed)
		)
		(placement
			(enabled no)
			(sheetname "")
		)
		(fill
			(thermal_gap 0.5)
			(thermal_bridge_width 0.5)
			(island_removal_mode 0)
		)
		(polygon
			(pts
				(arc
					(start 392.86561 -403.502876)
					(mid 392.48461 -403.883876)
					(end 392.86561 -404.264876)
				)
				(arc
					(start 393.72921 -404.264876)
					(mid 394.11021 -403.883876)
					(end 393.72921 -403.502876)
				)
			)
		)
	)
	(zone
		(layers "F.Cu" "B.Cu" "In1.Cu" "In2.Cu" "In3.Cu" "In4.Cu" "In5.Cu" "In6.Cu"
			"In7.Cu" "In8.Cu" "In9.Cu" "In10.Cu" "In11.Cu" "In12.Cu" "In13.Cu" "In14.Cu"
			"In15.Cu" "In16.Cu"
		)
		(hatch none 0.5)
		(connect_pads
			(clearance 0)
		)
		(min_thickness 0.25)
		(keepout
			(tracks not_allowed)
			(vias allowed)
			(pads allowed)
			(copperpour not_allowed)
			(footprints allowed)
		)
		(placement
			(enabled no)
			(sheetname "")
		)
		(fill
			(thermal_gap 0.5)
			(thermal_bridge_width 0.5)
			(island_removal_mode 0)
		)
		(polygon
			(pts
				(arc
					(start 90.823796 -213.732618)
					(mid 90.165936 -213.732618)
					(end 90.823796 -213.732618)
				)
			)
		)
	)
	(zone
		(layers "F.Cu" "B.Cu" "In1.Cu" "In2.Cu" "In3.Cu" "In4.Cu" "In5.Cu" "In6.Cu"
			"In7.Cu" "In8.Cu" "In9.Cu" "In10.Cu" "In11.Cu" "In12.Cu" "In13.Cu" "In14.Cu"
			"In15.Cu" "In16.Cu"
		)
		(hatch none 0.5)
		(connect_pads
			(clearance 0)
		)
		(min_thickness 0.25)
		(keepout
			(tracks not_allowed)
			(vias allowed)
			(pads allowed)
			(copperpour not_allowed)
			(footprints allowed)
		)
		(placement
			(enabled no)
			(sheetname "")
		)
		(fill
			(thermal_gap 0.5)
			(thermal_bridge_width 0.5)
			(island_removal_mode 0)
		)
		(polygon
			(pts
				(arc
					(start 102.101142 -223.575626)
					(mid 101.443282 -223.575626)
					(end 102.101142 -223.575626)
				)
			)
		)
	)
	(zone
		(layers "F.Cu" "B.Cu" "In1.Cu" "In2.Cu" "In3.Cu" "In4.Cu" "In5.Cu" "In6.Cu"
			"In7.Cu" "In8.Cu" "In9.Cu" "In10.Cu" "In11.Cu" "In12.Cu" "In13.Cu" "In14.Cu"
			"In15.Cu" "In16.Cu"
		)
		(hatch none 0.5)
		(connect_pads
			(clearance 0)
		)
		(min_thickness 0.25)
		(keepout
			(tracks not_allowed)
			(vias allowed)
			(pads allowed)
			(copperpour not_allowed)
			(footprints allowed)
		)
		(placement
			(enabled no)
			(sheetname "")
		)
		(fill
			(thermal_gap 0.5)
			(thermal_bridge_width 0.5)
			(island_removal_mode 0)
		)
		(polygon
			(pts
				(arc
					(start 112.720882 -220.319854)
					(mid 113.378742 -220.319854)
					(end 112.720882 -220.319854)
				)
			)
		)
	)
	(zone
		(layers "F.Cu" "B.Cu" "In1.Cu" "In2.Cu" "In3.Cu" "In4.Cu" "In5.Cu" "In6.Cu"
			"In7.Cu" "In8.Cu" "In9.Cu" "In10.Cu" "In11.Cu" "In12.Cu" "In13.Cu" "In14.Cu"
			"In15.Cu" "In16.Cu"
		)
		(hatch none 0.5)
		(connect_pads
			(clearance 0)
		)
		(min_thickness 0.25)
		(keepout
			(tracks not_allowed)
			(vias allowed)
			(pads allowed)
			(copperpour not_allowed)
			(footprints allowed)
		)
		(placement
			(enabled no)
			(sheetname "")
		)
		(fill
			(thermal_gap 0.5)
			(thermal_bridge_width 0.5)
			(island_removal_mode 0)
		)
		(polygon
			(pts
				(arc
					(start 126.377446 -223.67367)
					(mid 126.39713 -223.62626)
					(end 126.403862 -223.575372)
				)
				(arc
					(start 126.403862 -223.575372)
					(mid 126.346206 -223.436178)
					(end 126.207012 -223.378522)
				)
				(arc
					(start 126.207012 -223.378522)
					(mid 126.108581 -223.404938)
					(end 126.036578 -223.477074)
				)
				(arc
					(start 125.566932 -224.291144)
					(mid 125.547248 -224.338554)
					(end 125.540516 -224.389442)
				)
				(arc
					(start 125.540516 -224.389442)
					(mid 125.598172 -224.528636)
					(end 125.737366 -224.586292)
				)
				(arc
					(start 125.737366 -224.586292)
					(mid 125.835797 -224.559876)
					(end 125.9078 -224.48774)
				)
			)
		)
	)
	(zone
		(layers "F.Cu" "B.Cu" "In1.Cu" "In2.Cu" "In3.Cu" "In4.Cu" "In5.Cu" "In6.Cu"
			"In7.Cu" "In8.Cu" "In9.Cu" "In10.Cu" "In11.Cu" "In12.Cu" "In13.Cu" "In14.Cu"
			"In15.Cu" "In16.Cu"
		)
		(hatch none 0.5)
		(connect_pads
			(clearance 0)
		)
		(min_thickness 0.25)
		(keepout
			(tracks not_allowed)
			(vias allowed)
			(pads allowed)
			(copperpour not_allowed)
			(footprints allowed)
		)
		(placement
			(enabled no)
			(sheetname "")
		)
		(fill
			(thermal_gap 0.5)
			(thermal_bridge_width 0.5)
			(island_removal_mode 0)
		)
		(polygon
			(pts
				(arc
					(start 347.801692 -289.807142)
					(mid 347.143832 -289.807142)
					(end 347.801692 -289.807142)
				)
			)
		)
	)
	(zone
		(layers "F.Cu" "B.Cu" "In1.Cu" "In2.Cu" "In3.Cu" "In4.Cu" "In5.Cu" "In6.Cu"
			"In7.Cu" "In8.Cu" "In9.Cu" "In10.Cu" "In11.Cu" "In12.Cu" "In13.Cu" "In14.Cu"
			"In15.Cu" "In16.Cu"
		)
		(hatch none 0.5)
		(connect_pads
			(clearance 0)
		)
		(min_thickness 0.25)
		(keepout
			(tracks not_allowed)
			(vias allowed)
			(pads allowed)
			(copperpour not_allowed)
			(footprints allowed)
		)
		(placement
			(enabled no)
			(sheetname "")
		)
		(fill
			(thermal_gap 0.5)
			(thermal_bridge_width 0.5)
			(island_removal_mode 0)
		)
		(polygon
			(pts
				(arc
					(start 92.233496 -217.878406)
					(mid 91.575636 -217.878406)
					(end 92.233496 -217.878406)
				)
			)
		)
	)
	(zone
		(layers "F.Cu" "B.Cu" "In1.Cu" "In2.Cu" "In3.Cu" "In4.Cu" "In5.Cu" "In6.Cu"
			"In7.Cu" "In8.Cu" "In9.Cu" "In10.Cu" "In11.Cu" "In12.Cu" "In13.Cu" "In14.Cu"
			"In15.Cu" "In16.Cu"
		)
		(hatch none 0.5)
		(connect_pads
			(clearance 0)
		)
		(min_thickness 0.25)
		(keepout
			(tracks not_allowed)
			(vias allowed)
			(pads allowed)
			(copperpour not_allowed)
			(footprints allowed)
		)
		(placement
			(enabled no)
			(sheetname "")
		)
		(fill
			(thermal_gap 0.5)
			(thermal_bridge_width 0.5)
			(island_removal_mode 0)
		)
		(polygon
			(pts
				(arc
					(start 351.82302 -61.480954)
					(mid 352.20402 -61.861954)
					(end 352.58502 -61.480954)
				)
				(arc
					(start 352.58502 -60.617354)
					(mid 352.20402 -60.236354)
					(end 351.82302 -60.617354)
				)
			)
		)
	)
	(zone
		(layers "F.Cu" "B.Cu" "In1.Cu" "In2.Cu" "In3.Cu" "In4.Cu" "In5.Cu" "In6.Cu"
			"In7.Cu" "In8.Cu" "In9.Cu" "In10.Cu" "In11.Cu" "In12.Cu" "In13.Cu" "In14.Cu"
			"In15.Cu" "In16.Cu"
		)
		(hatch none 0.5)
		(connect_pads
			(clearance 0)
		)
		(min_thickness 0.25)
		(keepout
			(tracks not_allowed)
			(vias allowed)
			(pads allowed)
			(copperpour not_allowed)
			(footprints allowed)
		)
		(placement
			(enabled no)
			(sheetname "")
		)
		(fill
			(thermal_gap 0.5)
			(thermal_bridge_width 0.5)
			(island_removal_mode 0)
		)
		(polygon
			(pts
				(arc
					(start 354.850192 -282.405836)
					(mid 354.192332 -282.405836)
					(end 354.850192 -282.405836)
				)
			)
		)
	)
	(zone
		(layers "F.Cu" "B.Cu" "In1.Cu" "In2.Cu" "In3.Cu" "In4.Cu" "In5.Cu" "In6.Cu"
			"In7.Cu" "In8.Cu" "In9.Cu" "In10.Cu" "In11.Cu" "In12.Cu" "In13.Cu" "In14.Cu"
			"In15.Cu" "In16.Cu"
		)
		(hatch none 0.5)
		(connect_pads
			(clearance 0)
		)
		(min_thickness 0.25)
		(keepout
			(tracks allowed)
			(vias allowed)
			(pads allowed)
			(copperpour allowed)
			(footprints not_allowed)
		)
		(placement
			(enabled no)
			(sheetname "")
		)
		(fill
			(thermal_gap 0.5)
			(thermal_bridge_width 0.5)
			(island_removal_mode 0)
		)
		(polygon
			(pts
				(arc
					(start 286.98698 -74.760836)
					(mid 293.00297 -80.776826)
					(end 299.01896 -74.760836)
				)
				(arc
					(start 299.01896 -66.060828)
					(mid 293.00297 -60.044838)
					(end 286.98698 -66.060828)
				)
			)
		)
	)
	(zone
		(layers "F.Cu" "B.Cu" "In1.Cu" "In2.Cu" "In3.Cu" "In4.Cu" "In5.Cu" "In6.Cu"
			"In7.Cu" "In8.Cu" "In9.Cu" "In10.Cu" "In11.Cu" "In12.Cu" "In13.Cu" "In14.Cu"
			"In15.Cu" "In16.Cu"
		)
		(hatch none 0.5)
		(connect_pads
			(clearance 0)
		)
		(min_thickness 0.25)
		(keepout
			(tracks not_allowed)
			(vias allowed)
			(pads allowed)
			(copperpour not_allowed)
			(footprints allowed)
		)
		(placement
			(enabled no)
			(sheetname "")
		)
		(fill
			(thermal_gap 0.5)
			(thermal_bridge_width 0.5)
			(island_removal_mode 0)
		)
		(polygon
			(pts
				(arc
					(start 105.701846 -217.162634)
					(mid 105.72153 -217.115224)
					(end 105.728262 -217.064336)
				)
				(arc
					(start 105.728262 -217.064336)
					(mid 105.670606 -216.925142)
					(end 105.531412 -216.867486)
				)
				(arc
					(start 105.531412 -216.867486)
					(mid 105.432981 -216.893902)
					(end 105.360978 -216.966038)
				)
				(arc
					(start 104.891332 -217.780108)
					(mid 104.871648 -217.827518)
					(end 104.864916 -217.878406)
				)
				(arc
					(start 104.864916 -217.878406)
					(mid 104.922572 -218.0176)
					(end 105.061766 -218.075256)
				)
				(arc
					(start 105.061766 -218.075256)
					(mid 105.160197 -218.04884)
					(end 105.2322 -217.976704)
				)
			)
		)
	)
	(zone
		(layers "F.Cu" "B.Cu" "In1.Cu" "In2.Cu" "In3.Cu" "In4.Cu" "In5.Cu" "In6.Cu"
			"In7.Cu" "In8.Cu" "In9.Cu" "In10.Cu" "In11.Cu" "In12.Cu" "In13.Cu" "In14.Cu"
			"In15.Cu" "In16.Cu"
		)
		(hatch none 0.5)
		(connect_pads
			(clearance 0)
		)
		(min_thickness 0.25)
		(keepout
			(tracks not_allowed)
			(vias allowed)
			(pads allowed)
			(copperpour not_allowed)
			(footprints allowed)
		)
		(placement
			(enabled no)
			(sheetname "")
		)
		(fill
			(thermal_gap 0.5)
			(thermal_bridge_width 0.5)
			(island_removal_mode 0)
		)
		(polygon
			(pts
				(arc
					(start 116.668296 -217.878406)
					(mid 116.010436 -217.878406)
					(end 116.668296 -217.878406)
				)
			)
		)
	)
	(zone
		(layers "F.Cu" "B.Cu" "In1.Cu" "In2.Cu" "In3.Cu" "In4.Cu" "In5.Cu" "In6.Cu"
			"In7.Cu" "In8.Cu" "In9.Cu" "In10.Cu" "In11.Cu" "In12.Cu" "In13.Cu" "In14.Cu"
			"In15.Cu" "In16.Cu"
		)
		(hatch none 0.5)
		(connect_pads
			(clearance 0)
		)
		(min_thickness 0.25)
		(keepout
			(tracks not_allowed)
			(vias allowed)
			(pads allowed)
			(copperpour not_allowed)
			(footprints allowed)
		)
		(placement
			(enabled no)
			(sheetname "")
		)
		(fill
			(thermal_gap 0.5)
			(thermal_bridge_width 0.5)
			(island_removal_mode 0)
		)
		(polygon
			(pts
				(arc
					(start 100.691696 -217.878406)
					(mid 100.033836 -217.878406)
					(end 100.691696 -217.878406)
				)
			)
		)
	)
	(zone
		(layers "F.Cu" "B.Cu" "In1.Cu" "In2.Cu" "In3.Cu" "In4.Cu" "In5.Cu" "In6.Cu"
			"In7.Cu" "In8.Cu" "In9.Cu" "In10.Cu" "In11.Cu" "In12.Cu" "In13.Cu" "In14.Cu"
			"In15.Cu" "In16.Cu"
		)
		(hatch none 0.5)
		(connect_pads
			(clearance 0)
		)
		(min_thickness 0.25)
		(keepout
			(tracks not_allowed)
			(vias allowed)
			(pads allowed)
			(copperpour not_allowed)
			(footprints allowed)
		)
		(placement
			(enabled no)
			(sheetname "")
		)
		(fill
			(thermal_gap 0.5)
			(thermal_bridge_width 0.5)
			(island_removal_mode 0)
		)
		(polygon
			(pts
				(arc
					(start 106.252264 -275.8948)
					(mid 106.910124 -275.8948)
					(end 106.252264 -275.8948)
				)
			)
		)
	)
	(zone
		(layers "F.Cu" "B.Cu" "In1.Cu" "In2.Cu" "In3.Cu" "In4.Cu" "In5.Cu" "In6.Cu"
			"In7.Cu" "In8.Cu" "In9.Cu" "In10.Cu" "In11.Cu" "In12.Cu" "In13.Cu" "In14.Cu"
			"In15.Cu" "In16.Cu"
		)
		(hatch none 0.5)
		(connect_pads
			(clearance 0)
		)
		(min_thickness 0.25)
		(keepout
			(tracks not_allowed)
			(vias allowed)
			(pads allowed)
			(copperpour not_allowed)
			(footprints allowed)
		)
		(placement
			(enabled no)
			(sheetname "")
		)
		(fill
			(thermal_gap 0.5)
			(thermal_bridge_width 0.5)
			(island_removal_mode 0)
		)
		(polygon
			(pts
				(arc
					(start 397.27505 -409.649168)
					(mid 396.89405 -410.030168)
					(end 397.27505 -410.411168)
				)
				(arc
					(start 398.13865 -410.411168)
					(mid 398.51965 -410.030168)
					(end 398.13865 -409.649168)
				)
			)
		)
	)
	(zone
		(layers "F.Cu" "B.Cu" "In1.Cu" "In2.Cu" "In3.Cu" "In4.Cu" "In5.Cu" "In6.Cu"
			"In7.Cu" "In8.Cu" "In9.Cu" "In10.Cu" "In11.Cu" "In12.Cu" "In13.Cu" "In14.Cu"
			"In15.Cu" "In16.Cu"
		)
		(hatch none 0.5)
		(connect_pads
			(clearance 0)
		)
		(min_thickness 0.25)
		(keepout
			(tracks not_allowed)
			(vias allowed)
			(pads allowed)
			(copperpour not_allowed)
			(footprints allowed)
		)
		(placement
			(enabled no)
			(sheetname "")
		)
		(fill
			(thermal_gap 0.5)
			(thermal_bridge_width 0.5)
			(island_removal_mode 0)
		)
		(polygon
			(pts
				(arc
					(start 52.389278 -406.62352)
					(mid 52.008278 -407.00452)
					(end 52.389278 -407.38552)
				)
				(arc
					(start 53.252878 -407.38552)
					(mid 53.633878 -407.00452)
					(end 53.252878 -406.62352)
				)
			)
		)
	)
	(zone
		(layers "F.Cu" "B.Cu" "In1.Cu" "In2.Cu" "In3.Cu" "In4.Cu" "In5.Cu" "In6.Cu"
			"In7.Cu" "In8.Cu" "In9.Cu" "In10.Cu" "In11.Cu" "In12.Cu" "In13.Cu" "In14.Cu"
			"In15.Cu" "In16.Cu"
		)
		(hatch none 0.5)
		(connect_pads
			(clearance 0)
		)
		(min_thickness 0.25)
		(keepout
			(tracks not_allowed)
			(vias allowed)
			(pads allowed)
			(copperpour not_allowed)
			(footprints allowed)
		)
		(placement
			(enabled no)
			(sheetname "")
		)
		(fill
			(thermal_gap 0.5)
			(thermal_bridge_width 0.5)
			(island_removal_mode 0)
		)
		(polygon
			(pts
				(arc
					(start 108.961682 -220.319854)
					(mid 109.619542 -220.319854)
					(end 108.961682 -220.319854)
				)
			)
		)
	)
	(zone
		(layers "F.Cu" "B.Cu" "In1.Cu" "In2.Cu" "In3.Cu" "In4.Cu" "In5.Cu" "In6.Cu"
			"In7.Cu" "In8.Cu" "In9.Cu" "In10.Cu" "In11.Cu" "In12.Cu" "In13.Cu" "In14.Cu"
			"In15.Cu" "In16.Cu"
		)
		(hatch none 0.5)
		(connect_pads
			(clearance 0)
		)
		(min_thickness 0.25)
		(keepout
			(tracks not_allowed)
			(vias allowed)
			(pads allowed)
			(copperpour not_allowed)
			(footprints allowed)
		)
		(placement
			(enabled no)
			(sheetname "")
		)
		(fill
			(thermal_gap 0.5)
			(thermal_bridge_width 0.5)
			(island_removal_mode 0)
		)
		(polygon
			(pts
				(arc
					(start 87.801958 -400.477228)
					(mid 87.420958 -400.858228)
					(end 87.801958 -401.239228)
				)
				(arc
					(start 88.665558 -401.239228)
					(mid 89.046558 -400.858228)
					(end 88.665558 -400.477228)
				)
			)
		)
	)
	(zone
		(layers "F.Cu" "B.Cu" "In1.Cu" "In2.Cu" "In3.Cu" "In4.Cu" "In5.Cu" "In6.Cu"
			"In7.Cu" "In8.Cu" "In9.Cu" "In10.Cu" "In11.Cu" "In12.Cu" "In13.Cu" "In14.Cu"
			"In15.Cu" "In16.Cu"
		)
		(hatch none 0.5)
		(connect_pads
			(clearance 0)
		)
		(min_thickness 0.25)
		(keepout
			(tracks not_allowed)
			(vias allowed)
			(pads allowed)
			(copperpour not_allowed)
			(footprints allowed)
		)
		(placement
			(enabled no)
			(sheetname "")
		)
		(fill
			(thermal_gap 0.5)
			(thermal_bridge_width 0.5)
			(island_removal_mode 0)
		)
		(polygon
			(pts
				(arc
					(start 96.774 -217.780108)
					(mid 96.702011 -217.707949)
					(end 96.603566 -217.681556)
				)
				(arc
					(start 96.603566 -217.681556)
					(mid 96.464372 -217.739212)
					(end 96.406716 -217.878406)
				)
				(arc
					(start 96.406716 -217.878406)
					(mid 96.413473 -217.929287)
					(end 96.433132 -217.976704)
				)
				(arc
					(start 96.902778 -218.79052)
					(mid 96.974767 -218.862679)
					(end 97.073212 -218.889072)
				)
				(arc
					(start 97.073212 -218.889072)
					(mid 97.212406 -218.831416)
					(end 97.270062 -218.692222)
				)
				(arc
					(start 97.270062 -218.692222)
					(mid 97.263305 -218.641341)
					(end 97.243646 -218.593924)
				)
			)
		)
	)
	(zone
		(layers "F.Cu" "B.Cu" "In1.Cu" "In2.Cu" "In3.Cu" "In4.Cu" "In5.Cu" "In6.Cu"
			"In7.Cu" "In8.Cu" "In9.Cu" "In10.Cu" "In11.Cu" "In12.Cu" "In13.Cu" "In14.Cu"
			"In15.Cu" "In16.Cu"
		)
		(hatch none 0.5)
		(connect_pads
			(clearance 0)
		)
		(min_thickness 0.25)
		(keepout
			(tracks not_allowed)
			(vias allowed)
			(pads allowed)
			(copperpour not_allowed)
			(footprints allowed)
		)
		(placement
			(enabled no)
			(sheetname "")
		)
		(fill
			(thermal_gap 0.5)
			(thermal_bridge_width 0.5)
			(island_removal_mode 0)
		)
		(polygon
			(pts
				(arc
					(start 372.547896 -285.759652)
					(mid 372.56758 -285.712242)
					(end 372.574312 -285.661354)
				)
				(arc
					(start 372.574312 -285.661354)
					(mid 372.516656 -285.52216)
					(end 372.377462 -285.464504)
				)
				(arc
					(start 372.377462 -285.464504)
					(mid 372.279031 -285.49092)
					(end 372.207028 -285.563056)
				)
				(arc
					(start 371.737382 -286.377126)
					(mid 371.717698 -286.424536)
					(end 371.710966 -286.475424)
				)
				(arc
					(start 371.710966 -286.475424)
					(mid 371.768622 -286.614618)
					(end 371.907816 -286.672274)
				)
				(arc
					(start 371.907816 -286.672274)
					(mid 372.006247 -286.645858)
					(end 372.07825 -286.573722)
				)
			)
		)
	)
	(zone
		(layers "F.Cu" "B.Cu" "In1.Cu" "In2.Cu" "In3.Cu" "In4.Cu" "In5.Cu" "In6.Cu"
			"In7.Cu" "In8.Cu" "In9.Cu" "In10.Cu" "In11.Cu" "In12.Cu" "In13.Cu" "In14.Cu"
			"In15.Cu" "In16.Cu"
		)
		(hatch none 0.5)
		(connect_pads
			(clearance 0)
		)
		(min_thickness 0.25)
		(keepout
			(tracks not_allowed)
			(vias allowed)
			(pads allowed)
			(copperpour not_allowed)
			(footprints allowed)
		)
		(placement
			(enabled no)
			(sheetname "")
		)
		(fill
			(thermal_gap 0.5)
			(thermal_bridge_width 0.5)
			(island_removal_mode 0)
		)
		(polygon
			(pts
				(arc
					(start 128.697482 -215.436704)
					(mid 129.355342 -215.436704)
					(end 128.697482 -215.436704)
				)
			)
		)
	)
	(zone
		(layers "F.Cu" "B.Cu" "In1.Cu" "In2.Cu" "In3.Cu" "In4.Cu" "In5.Cu" "In6.Cu"
			"In7.Cu" "In8.Cu" "In9.Cu" "In10.Cu" "In11.Cu" "In12.Cu" "In13.Cu" "In14.Cu"
			"In15.Cu" "In16.Cu"
		)
		(hatch none 0.5)
		(connect_pads
			(clearance 0)
		)
		(min_thickness 0.25)
		(keepout
			(tracks not_allowed)
			(vias allowed)
			(pads allowed)
			(copperpour not_allowed)
			(footprints allowed)
		)
		(placement
			(enabled no)
			(sheetname "")
		)
		(fill
			(thermal_gap 0.5)
			(thermal_bridge_width 0.5)
			(island_removal_mode 0)
		)
		(polygon
			(pts
				(xy 782.711922 -388.695946) (xy 777.712186 -388.695946) (xy 778.016986 -388.391146) (xy 782.407122 -388.391146)
			)
		)
	)
	(zone
		(layers "F.Cu" "B.Cu" "In1.Cu" "In2.Cu" "In3.Cu" "In4.Cu" "In5.Cu" "In6.Cu"
			"In7.Cu" "In8.Cu" "In9.Cu" "In10.Cu" "In11.Cu" "In12.Cu" "In13.Cu" "In14.Cu"
			"In15.Cu" "In16.Cu"
		)
		(hatch none 0.5)
		(connect_pads
			(clearance 0)
		)
		(min_thickness 0.25)
		(keepout
			(tracks not_allowed)
			(vias allowed)
			(pads allowed)
			(copperpour not_allowed)
			(footprints allowed)
		)
		(placement
			(enabled no)
			(sheetname "")
		)
		(fill
			(thermal_gap 0.5)
			(thermal_bridge_width 0.5)
			(island_removal_mode 0)
		)
		(polygon
			(pts
				(arc
					(start 130.687318 -288.917126)
					(mid 131.345178 -288.917126)
					(end 130.687318 -288.917126)
				)
			)
		)
	)
	(zone
		(layers "F.Cu" "B.Cu" "In1.Cu" "In2.Cu" "In3.Cu" "In4.Cu" "In5.Cu" "In6.Cu"
			"In7.Cu" "In8.Cu" "In9.Cu" "In10.Cu" "In11.Cu" "In12.Cu" "In13.Cu" "In14.Cu"
			"In15.Cu" "In16.Cu"
		)
		(hatch none 0.5)
		(connect_pads
			(clearance 0)
		)
		(min_thickness 0.25)
		(keepout
			(tracks not_allowed)
			(vias allowed)
			(pads allowed)
			(copperpour not_allowed)
			(footprints allowed)
		)
		(placement
			(enabled no)
			(sheetname "")
		)
		(fill
			(thermal_gap 0.5)
			(thermal_bridge_width 0.5)
			(island_removal_mode 0)
		)
		(polygon
			(pts
				(arc
					(start 104.2924 -217.780108)
					(mid 104.220411 -217.707949)
					(end 104.121966 -217.681556)
				)
				(arc
					(start 104.121966 -217.681556)
					(mid 103.982772 -217.739212)
					(end 103.925116 -217.878406)
				)
				(arc
					(start 103.925116 -217.878406)
					(mid 103.931873 -217.929287)
					(end 103.951532 -217.976704)
				)
				(arc
					(start 104.421178 -218.79052)
					(mid 104.493167 -218.862679)
					(end 104.591612 -218.889072)
				)
				(arc
					(start 104.591612 -218.889072)
					(mid 104.730806 -218.831416)
					(end 104.788462 -218.692222)
				)
				(arc
					(start 104.788462 -218.692222)
					(mid 104.781705 -218.641341)
					(end 104.762046 -218.593924)
				)
			)
		)
	)
	(zone
		(layers "F.Cu" "B.Cu" "In1.Cu" "In2.Cu" "In3.Cu" "In4.Cu" "In5.Cu" "In6.Cu"
			"In7.Cu" "In8.Cu" "In9.Cu" "In10.Cu" "In11.Cu" "In12.Cu" "In13.Cu" "In14.Cu"
			"In15.Cu" "In16.Cu"
		)
		(hatch none 0.5)
		(connect_pads
			(clearance 0)
		)
		(min_thickness 0.25)
		(keepout
			(tracks not_allowed)
			(vias allowed)
			(pads allowed)
			(copperpour not_allowed)
			(footprints allowed)
		)
		(placement
			(enabled no)
			(sheetname "")
		)
		(fill
			(thermal_gap 0.5)
			(thermal_bridge_width 0.5)
			(island_removal_mode 0)
		)
		(polygon
			(pts
				(arc
					(start 102.493318 -288.917126)
					(mid 103.151178 -288.917126)
					(end 102.493318 -288.917126)
				)
			)
		)
	)
	(zone
		(layers "F.Cu" "B.Cu" "In1.Cu" "In2.Cu" "In3.Cu" "In4.Cu" "In5.Cu" "In6.Cu"
			"In7.Cu" "In8.Cu" "In9.Cu" "In10.Cu" "In11.Cu" "In12.Cu" "In13.Cu" "In14.Cu"
			"In15.Cu" "In16.Cu"
		)
		(hatch none 0.5)
		(connect_pads
			(clearance 0)
		)
		(min_thickness 0.25)
		(keepout
			(tracks not_allowed)
			(vias allowed)
			(pads allowed)
			(copperpour not_allowed)
			(footprints allowed)
		)
		(placement
			(enabled no)
			(sheetname "")
		)
		(fill
			(thermal_gap 0.5)
			(thermal_bridge_width 0.5)
			(island_removal_mode 0)
		)
		(polygon
			(pts
				(arc
					(start 359.439464 -217.064336)
					(mid 358.781604 -217.064336)
					(end 359.439464 -217.064336)
				)
			)
		)
	)
	(zone
		(layers "F.Cu" "B.Cu" "In1.Cu" "In2.Cu" "In3.Cu" "In4.Cu" "In5.Cu" "In6.Cu"
			"In7.Cu" "In8.Cu" "In9.Cu" "In10.Cu" "In11.Cu" "In12.Cu" "In13.Cu" "In14.Cu"
			"In15.Cu" "In16.Cu"
		)
		(hatch none 0.5)
		(connect_pads
			(clearance 0)
		)
		(min_thickness 0.25)
		(keepout
			(tracks not_allowed)
			(vias allowed)
			(pads allowed)
			(copperpour not_allowed)
			(footprints allowed)
		)
		(placement
			(enabled no)
			(sheetname "")
		)
		(fill
			(thermal_gap 0.5)
			(thermal_bridge_width 0.5)
			(island_removal_mode 0)
		)
		(polygon
			(pts
				(arc
					(start 109.931454 -217.780108)
					(mid 109.859465 -217.707949)
					(end 109.76102 -217.681556)
				)
				(arc
					(start 109.76102 -217.681556)
					(mid 109.621826 -217.739212)
					(end 109.56417 -217.878406)
				)
				(arc
					(start 109.56417 -217.878406)
					(mid 109.570927 -217.929287)
					(end 109.590586 -217.976704)
				)
				(arc
					(start 110.060232 -218.79052)
					(mid 110.132221 -218.862679)
					(end 110.230666 -218.889072)
				)
				(arc
					(start 110.230666 -218.889072)
					(mid 110.36986 -218.831416)
					(end 110.427516 -218.692222)
				)
				(arc
					(start 110.427516 -218.692222)
					(mid 110.420759 -218.641341)
					(end 110.4011 -218.593924)
				)
			)
		)
	)
	(zone
		(layers "F.Cu" "B.Cu" "In1.Cu" "In2.Cu" "In3.Cu" "In4.Cu" "In5.Cu" "In6.Cu"
			"In7.Cu" "In8.Cu" "In9.Cu" "In10.Cu" "In11.Cu" "In12.Cu" "In13.Cu" "In14.Cu"
			"In15.Cu" "In16.Cu"
		)
		(hatch none 0.5)
		(connect_pads
			(clearance 0)
		)
		(min_thickness 0.25)
		(keepout
			(tracks not_allowed)
			(vias allowed)
			(pads allowed)
			(copperpour not_allowed)
			(footprints allowed)
		)
		(placement
			(enabled no)
			(sheetname "")
		)
		(fill
			(thermal_gap 0.5)
			(thermal_bridge_width 0.5)
			(island_removal_mode 0)
		)
		(polygon
			(pts
				(arc
					(start 354.74021 -215.436704)
					(mid 354.08235 -215.436704)
					(end 354.74021 -215.436704)
				)
			)
		)
	)
	(zone
		(layers "F.Cu" "B.Cu" "In1.Cu" "In2.Cu" "In3.Cu" "In4.Cu" "In5.Cu" "In6.Cu"
			"In7.Cu" "In8.Cu" "In9.Cu" "In10.Cu" "In11.Cu" "In12.Cu" "In13.Cu" "In14.Cu"
			"In15.Cu" "In16.Cu"
		)
		(hatch none 0.5)
		(connect_pads
			(clearance 0)
		)
		(min_thickness 0.25)
		(keepout
			(tracks not_allowed)
			(vias allowed)
			(pads allowed)
			(copperpour not_allowed)
			(footprints allowed)
		)
		(placement
			(enabled no)
			(sheetname "")
		)
		(fill
			(thermal_gap 0.5)
			(thermal_bridge_width 0.5)
			(island_removal_mode 0)
		)
		(polygon
			(pts
				(arc
					(start 108.209588 -214.622634)
					(mid 107.551728 -214.622634)
					(end 108.209588 -214.622634)
				)
			)
		)
	)
	(zone
		(layers "F.Cu" "B.Cu" "In1.Cu" "In2.Cu" "In3.Cu" "In4.Cu" "In5.Cu" "In6.Cu"
			"In7.Cu" "In8.Cu" "In9.Cu" "In10.Cu" "In11.Cu" "In12.Cu" "In13.Cu" "In14.Cu"
			"In15.Cu" "In16.Cu"
		)
		(hatch none 0.5)
		(connect_pads
			(clearance 0)
		)
		(min_thickness 0.25)
		(keepout
			(tracks not_allowed)
			(vias allowed)
			(pads allowed)
			(copperpour not_allowed)
			(footprints allowed)
		)
		(placement
			(enabled no)
			(sheetname "")
		)
		(fill
			(thermal_gap 0.5)
			(thermal_bridge_width 0.5)
			(island_removal_mode 0)
		)
		(polygon
			(pts
				(arc
					(start 93.642942 -221.94774)
					(mid 92.985082 -221.94774)
					(end 93.642942 -221.94774)
				)
			)
		)
	)
	(zone
		(layers "F.Cu" "B.Cu" "In1.Cu" "In2.Cu" "In3.Cu" "In4.Cu" "In5.Cu" "In6.Cu"
			"In7.Cu" "In8.Cu" "In9.Cu" "In10.Cu" "In11.Cu" "In12.Cu" "In13.Cu" "In14.Cu"
			"In15.Cu" "In16.Cu"
		)
		(hatch none 0.5)
		(connect_pads
			(clearance 0)
		)
		(min_thickness 0.25)
		(keepout
			(tracks not_allowed)
			(vias allowed)
			(pads allowed)
			(copperpour not_allowed)
			(footprints allowed)
		)
		(placement
			(enabled no)
			(sheetname "")
		)
		(fill
			(thermal_gap 0.5)
			(thermal_bridge_width 0.5)
			(island_removal_mode 0)
		)
		(polygon
			(pts
				(arc
					(start 12.53744 -109.297724)
					(mid 12.91844 -108.916724)
					(end 12.53744 -108.535724)
				)
				(arc
					(start 11.67384 -108.535724)
					(mid 11.29284 -108.916724)
					(end 11.67384 -109.297724)
				)
			)
		)
	)
	(zone
		(layers "F.Cu" "B.Cu" "In1.Cu" "In2.Cu" "In3.Cu" "In4.Cu" "In5.Cu" "In6.Cu"
			"In7.Cu" "In8.Cu" "In9.Cu" "In10.Cu" "In11.Cu" "In12.Cu" "In13.Cu" "In14.Cu"
			"In15.Cu" "In16.Cu"
		)
		(hatch none 0.5)
		(connect_pads
			(clearance 0)
		)
		(min_thickness 0.25)
		(keepout
			(tracks not_allowed)
			(vias allowed)
			(pads allowed)
			(copperpour not_allowed)
			(footprints allowed)
		)
		(placement
			(enabled no)
			(sheetname "")
		)
		(fill
			(thermal_gap 0.5)
			(thermal_bridge_width 0.5)
			(island_removal_mode 0)
		)
		(polygon
			(pts
				(arc
					(start 102.352348 -274.88388)
					(mid 102.155498 -275.08073)
					(end 102.352348 -275.27758)
				)
				(arc
					(start 103.292148 -275.27758)
					(mid 103.488998 -275.08073)
					(end 103.292148 -274.88388)
				)
			)
		)
	)
	(zone
		(layers "F.Cu" "B.Cu" "In1.Cu" "In2.Cu" "In3.Cu" "In4.Cu" "In5.Cu" "In6.Cu"
			"In7.Cu" "In8.Cu" "In9.Cu" "In10.Cu" "In11.Cu" "In12.Cu" "In13.Cu" "In14.Cu"
			"In15.Cu" "In16.Cu"
		)
		(hatch none 0.5)
		(connect_pads
			(clearance 0)
		)
		(min_thickness 0.25)
		(keepout
			(tracks not_allowed)
			(vias allowed)
			(pads allowed)
			(copperpour not_allowed)
			(footprints allowed)
		)
		(placement
			(enabled no)
			(sheetname "")
		)
		(fill
			(thermal_gap 0.5)
			(thermal_bridge_width 0.5)
			(island_removal_mode 0)
		)
		(polygon
			(pts
				(arc
					(start 129.355342 -221.94774)
					(mid 128.697482 -221.94774)
					(end 129.355342 -221.94774)
				)
			)
		)
	)
	(zone
		(layers "F.Cu" "B.Cu" "In1.Cu" "In2.Cu" "In3.Cu" "In4.Cu" "In5.Cu" "In6.Cu"
			"In7.Cu" "In8.Cu" "In9.Cu" "In10.Cu" "In11.Cu" "In12.Cu" "In13.Cu" "In14.Cu"
			"In15.Cu" "In16.Cu"
		)
		(hatch none 0.5)
		(connect_pads
			(clearance 0)
		)
		(min_thickness 0.25)
		(keepout
			(tracks not_allowed)
			(vias allowed)
			(pads allowed)
			(copperpour not_allowed)
			(footprints allowed)
		)
		(placement
			(enabled no)
			(sheetname "")
		)
		(fill
			(thermal_gap 0.5)
			(thermal_bridge_width 0.5)
			(island_removal_mode 0)
		)
		(polygon
			(pts
				(arc
					(start 355.05136 -221.231968)
					(mid 355.071044 -221.184558)
					(end 355.077776 -221.13367)
				)
				(arc
					(start 355.077776 -221.13367)
					(mid 355.02012 -220.994476)
					(end 354.880926 -220.93682)
				)
				(arc
					(start 354.880926 -220.93682)
					(mid 354.782495 -220.963236)
					(end 354.710492 -221.035372)
				)
				(arc
					(start 354.240846 -221.849442)
					(mid 354.221162 -221.896852)
					(end 354.21443 -221.94774)
				)
				(arc
					(start 354.21443 -221.94774)
					(mid 354.272086 -222.086934)
					(end 354.41128 -222.14459)
				)
				(arc
					(start 354.41128 -222.14459)
					(mid 354.509711 -222.118174)
					(end 354.581714 -222.046038)
				)
			)
		)
	)
	(zone
		(layers "F.Cu" "B.Cu" "In1.Cu" "In2.Cu" "In3.Cu" "In4.Cu" "In5.Cu" "In6.Cu"
			"In7.Cu" "In8.Cu" "In9.Cu" "In10.Cu" "In11.Cu" "In12.Cu" "In13.Cu" "In14.Cu"
			"In15.Cu" "In16.Cu"
		)
		(hatch none 0.5)
		(connect_pads
			(clearance 0)
		)
		(min_thickness 0.25)
		(keepout
			(tracks not_allowed)
			(vias allowed)
			(pads allowed)
			(copperpour not_allowed)
			(footprints allowed)
		)
		(placement
			(enabled no)
			(sheetname "")
		)
		(fill
			(thermal_gap 0.5)
			(thermal_bridge_width 0.5)
			(island_removal_mode 0)
		)
		(polygon
			(pts
				(arc
					(start 15.61338 -21.112988)
					(mid 15.23238 -21.493988)
					(end 15.61338 -21.874988)
				)
				(arc
					(start 16.47698 -21.874988)
					(mid 16.85798 -21.493988)
					(end 16.47698 -21.112988)
				)
			)
		)
	)
	(zone
		(layers "F.Cu" "B.Cu" "In1.Cu" "In2.Cu" "In3.Cu" "In4.Cu" "In5.Cu" "In6.Cu"
			"In7.Cu" "In8.Cu" "In9.Cu" "In10.Cu" "In11.Cu" "In12.Cu" "In13.Cu" "In14.Cu"
			"In15.Cu" "In16.Cu"
		)
		(hatch none 0.5)
		(connect_pads
			(clearance 0)
		)
		(min_thickness 0.25)
		(keepout
			(tracks not_allowed)
			(vias allowed)
			(pads allowed)
			(copperpour not_allowed)
			(footprints allowed)
		)
		(placement
			(enabled no)
			(sheetname "")
		)
		(fill
			(thermal_gap 0.5)
			(thermal_bridge_width 0.5)
			(island_removal_mode 0)
		)
		(polygon
			(pts
				(arc
					(start 57.335674 -12.483084)
					(mid 56.954674 -12.864084)
					(end 57.335674 -13.245084)
				)
				(arc
					(start 58.199274 -13.245084)
					(mid 58.580274 -12.864084)
					(end 58.199274 -12.483084)
				)
			)
		)
	)
	(zone
		(layers "F.Cu" "B.Cu" "In1.Cu" "In2.Cu" "In3.Cu" "In4.Cu" "In5.Cu" "In6.Cu"
			"In7.Cu" "In8.Cu" "In9.Cu" "In10.Cu" "In11.Cu" "In12.Cu" "In13.Cu" "In14.Cu"
			"In15.Cu" "In16.Cu"
		)
		(hatch none 0.5)
		(connect_pads
			(clearance 0)
		)
		(min_thickness 0.25)
		(keepout
			(tracks not_allowed)
			(vias allowed)
			(pads allowed)
			(copperpour not_allowed)
			(footprints allowed)
		)
		(placement
			(enabled no)
			(sheetname "")
		)
		(fill
			(thermal_gap 0.5)
			(thermal_bridge_width 0.5)
			(island_removal_mode 0)
		)
		(polygon
			(pts
				(arc
					(start 98.811588 -214.622634)
					(mid 98.153728 -214.622634)
					(end 98.811588 -214.622634)
				)
			)
		)
	)
	(zone
		(layers "F.Cu" "B.Cu" "In1.Cu" "In2.Cu" "In3.Cu" "In4.Cu" "In5.Cu" "In6.Cu"
			"In7.Cu" "In8.Cu" "In9.Cu" "In10.Cu" "In11.Cu" "In12.Cu" "In13.Cu" "In14.Cu"
			"In15.Cu" "In16.Cu"
		)
		(hatch none 0.5)
		(connect_pads
			(clearance 0)
		)
		(min_thickness 0.25)
		(keepout
			(tracks not_allowed)
			(vias allowed)
			(pads allowed)
			(copperpour not_allowed)
			(footprints allowed)
		)
		(placement
			(enabled no)
			(sheetname "")
		)
		(fill
			(thermal_gap 0.5)
			(thermal_bridge_width 0.5)
			(island_removal_mode 0)
		)
		(polygon
			(pts
				(arc
					(start 23.494492 -384.946398)
					(mid 23.113492 -384.565398)
					(end 22.732492 -384.946398)
				)
				(arc
					(start 22.732492 -385.809998)
					(mid 23.113492 -386.190998)
					(end 23.494492 -385.809998)
				)
			)
		)
	)
	(zone
		(layers "F.Cu" "B.Cu" "In1.Cu" "In2.Cu" "In3.Cu" "In4.Cu" "In5.Cu" "In6.Cu"
			"In7.Cu" "In8.Cu" "In9.Cu" "In10.Cu" "In11.Cu" "In12.Cu" "In13.Cu" "In14.Cu"
			"In15.Cu" "In16.Cu"
		)
		(hatch none 0.5)
		(connect_pads
			(clearance 0)
		)
		(min_thickness 0.25)
		(keepout
			(tracks not_allowed)
			(vias allowed)
			(pads allowed)
			(copperpour not_allowed)
			(footprints allowed)
		)
		(placement
			(enabled no)
			(sheetname "")
		)
		(fill
			(thermal_gap 0.5)
			(thermal_bridge_width 0.5)
			(island_removal_mode 0)
		)
		(polygon
			(pts
				(arc
					(start 120.739154 -216.966292)
					(mid 120.667165 -216.894133)
					(end 120.56872 -216.86774)
				)
				(arc
					(start 120.56872 -216.86774)
					(mid 120.429526 -216.925396)
					(end 120.37187 -217.06459)
				)
				(arc
					(start 120.37187 -217.06459)
					(mid 120.378627 -217.115471)
					(end 120.398286 -217.162888)
				)
				(arc
					(start 120.867932 -217.976704)
					(mid 120.939921 -218.048863)
					(end 121.038366 -218.075256)
				)
				(arc
					(start 121.038366 -218.075256)
					(mid 121.17756 -218.0176)
					(end 121.235216 -217.878406)
				)
				(arc
					(start 121.235216 -217.878406)
					(mid 121.228459 -217.827525)
					(end 121.2088 -217.780108)
				)
			)
		)
	)
	(zone
		(layers "F.Cu" "B.Cu" "In1.Cu" "In2.Cu" "In3.Cu" "In4.Cu" "In5.Cu" "In6.Cu"
			"In7.Cu" "In8.Cu" "In9.Cu" "In10.Cu" "In11.Cu" "In12.Cu" "In13.Cu" "In14.Cu"
			"In15.Cu" "In16.Cu"
		)
		(hatch none 0.5)
		(connect_pads
			(clearance 0)
		)
		(min_thickness 0.25)
		(keepout
			(tracks not_allowed)
			(vias allowed)
			(pads allowed)
			(copperpour not_allowed)
			(footprints allowed)
		)
		(placement
			(enabled no)
			(sheetname "")
		)
		(fill
			(thermal_gap 0.5)
			(thermal_bridge_width 0.5)
			(island_removal_mode 0)
		)
		(polygon
			(pts
				(arc
					(start 83.021678 -406.62352)
					(mid 82.640678 -407.00452)
					(end 83.021678 -407.38552)
				)
				(arc
					(start 83.885278 -407.38552)
					(mid 84.266278 -407.00452)
					(end 83.885278 -406.62352)
				)
			)
		)
	)
	(zone
		(layers "F.Cu" "B.Cu" "In1.Cu" "In2.Cu" "In3.Cu" "In4.Cu" "In5.Cu" "In6.Cu"
			"In7.Cu" "In8.Cu" "In9.Cu" "In10.Cu" "In11.Cu" "In12.Cu" "In13.Cu" "In14.Cu"
			"In15.Cu" "In16.Cu"
		)
		(hatch none 0.5)
		(connect_pads
			(clearance 0)
		)
		(min_thickness 0.25)
		(keepout
			(tracks not_allowed)
			(vias allowed)
			(pads allowed)
			(copperpour not_allowed)
			(footprints allowed)
		)
		(placement
			(enabled no)
			(sheetname "")
		)
		(fill
			(thermal_gap 0.5)
			(thermal_bridge_width 0.5)
			(island_removal_mode 0)
		)
		(polygon
			(pts
				(arc
					(start 380.426468 -224.291144)
					(mid 380.354479 -224.218985)
					(end 380.256034 -224.192592)
				)
				(arc
					(start 380.256034 -224.192592)
					(mid 380.11684 -224.250248)
					(end 380.059184 -224.389442)
				)
				(arc
					(start 380.059184 -224.389442)
					(mid 380.065941 -224.440323)
					(end 380.0856 -224.48774)
				)
				(arc
					(start 380.555246 -225.301556)
					(mid 380.627235 -225.373715)
					(end 380.72568 -225.400108)
				)
				(arc
					(start 380.72568 -225.400108)
					(mid 380.864874 -225.342452)
					(end 380.92253 -225.203258)
				)
				(arc
					(start 380.92253 -225.203258)
					(mid 380.915773 -225.152377)
					(end 380.896114 -225.10496)
				)
			)
		)
	)
	(zone
		(layers "F.Cu" "B.Cu" "In1.Cu" "In2.Cu" "In3.Cu" "In4.Cu" "In5.Cu" "In6.Cu"
			"In7.Cu" "In8.Cu" "In9.Cu" "In10.Cu" "In11.Cu" "In12.Cu" "In13.Cu" "In14.Cu"
			"In15.Cu" "In16.Cu"
		)
		(hatch none 0.5)
		(connect_pads
			(clearance 0)
		)
		(min_thickness 0.25)
		(keepout
			(tracks not_allowed)
			(vias allowed)
			(pads allowed)
			(copperpour not_allowed)
			(footprints allowed)
		)
		(placement
			(enabled no)
			(sheetname "")
		)
		(fill
			(thermal_gap 0.5)
			(thermal_bridge_width 0.5)
			(island_removal_mode 0)
		)
		(polygon
			(pts
				(arc
					(start 376.2121 5.031994)
					(mid 376.5931 4.650994)
					(end 376.9741 5.031994)
				)
				(arc
					(start 376.9741 5.895594)
					(mid 376.5931 6.276594)
					(end 376.2121 5.895594)
				)
			)
		)
	)
	(zone
		(layers "F.Cu" "B.Cu" "In1.Cu" "In2.Cu" "In3.Cu" "In4.Cu" "In5.Cu" "In6.Cu"
			"In7.Cu" "In8.Cu" "In9.Cu" "In10.Cu" "In11.Cu" "In12.Cu" "In13.Cu" "In14.Cu"
			"In15.Cu" "In16.Cu"
		)
		(hatch none 0.5)
		(connect_pads
			(clearance 0)
		)
		(min_thickness 0.25)
		(keepout
			(tracks not_allowed)
			(vias allowed)
			(pads allowed)
			(copperpour not_allowed)
			(footprints allowed)
		)
		(placement
			(enabled no)
			(sheetname "")
		)
		(fill
			(thermal_gap 0.5)
			(thermal_bridge_width 0.5)
			(island_removal_mode 0)
		)
		(polygon
			(pts
				(arc
					(start 319.296288 -400.477228)
					(mid 318.915288 -400.858228)
					(end 319.296288 -401.239228)
				)
				(arc
					(start 320.159888 -401.239228)
					(mid 320.540888 -400.858228)
					(end 320.159888 -400.477228)
				)
			)
		)
	)
	(zone
		(layers "F.Cu" "B.Cu" "In1.Cu" "In2.Cu" "In3.Cu" "In4.Cu" "In5.Cu" "In6.Cu"
			"In7.Cu" "In8.Cu" "In9.Cu" "In10.Cu" "In11.Cu" "In12.Cu" "In13.Cu" "In14.Cu"
			"In15.Cu" "In16.Cu"
		)
		(hatch none 0.5)
		(connect_pads
			(clearance 0)
		)
		(min_thickness 0.25)
		(keepout
			(tracks not_allowed)
			(vias allowed)
			(pads allowed)
			(copperpour not_allowed)
			(footprints allowed)
		)
		(placement
			(enabled no)
			(sheetname "")
		)
		(fill
			(thermal_gap 0.5)
			(thermal_bridge_width 0.5)
			(island_removal_mode 0)
		)
		(polygon
			(pts
				(arc
					(start 134.524496 -217.878406)
					(mid 133.866636 -217.878406)
					(end 134.524496 -217.878406)
				)
			)
		)
	)
	(zone
		(layers "F.Cu" "B.Cu" "In1.Cu" "In2.Cu" "In3.Cu" "In4.Cu" "In5.Cu" "In6.Cu"
			"In7.Cu" "In8.Cu" "In9.Cu" "In10.Cu" "In11.Cu" "In12.Cu" "In13.Cu" "In14.Cu"
			"In15.Cu" "In16.Cu"
		)
		(hatch none 0.5)
		(connect_pads
			(clearance 0)
		)
		(min_thickness 0.25)
		(keepout
			(tracks not_allowed)
			(vias allowed)
			(pads allowed)
			(copperpour not_allowed)
			(footprints allowed)
		)
		(placement
			(enabled no)
			(sheetname "")
		)
		(fill
			(thermal_gap 0.5)
			(thermal_bridge_width 0.5)
			(island_removal_mode 0)
		)
		(polygon
			(pts
				(arc
					(start 161.323274 -406.62352)
					(mid 160.942274 -407.00452)
					(end 161.323274 -407.38552)
				)
				(arc
					(start 162.186874 -407.38552)
					(mid 162.567874 -407.00452)
					(end 162.186874 -406.62352)
				)
			)
		)
	)
	(zone
		(layers "F.Cu" "B.Cu" "In1.Cu" "In2.Cu" "In3.Cu" "In4.Cu" "In5.Cu" "In6.Cu"
			"In7.Cu" "In8.Cu" "In9.Cu" "In10.Cu" "In11.Cu" "In12.Cu" "In13.Cu" "In14.Cu"
			"In15.Cu" "In16.Cu"
		)
		(hatch none 0.5)
		(connect_pads
			(clearance 0)
		)
		(min_thickness 0.25)
		(keepout
			(tracks not_allowed)
			(vias allowed)
			(pads allowed)
			(copperpour not_allowed)
			(footprints allowed)
		)
		(placement
			(enabled no)
			(sheetname "")
		)
		(fill
			(thermal_gap 0.5)
			(thermal_bridge_width 0.5)
			(island_removal_mode 0)
		)
		(polygon
			(pts
				(arc
					(start 345.811856 -214.622634)
					(mid 345.153996 -214.622634)
					(end 345.811856 -214.622634)
				)
			)
		)
	)
	(zone
		(layers "F.Cu" "B.Cu" "In1.Cu" "In2.Cu" "In3.Cu" "In4.Cu" "In5.Cu" "In6.Cu"
			"In7.Cu" "In8.Cu" "In9.Cu" "In10.Cu" "In11.Cu" "In12.Cu" "In13.Cu" "In14.Cu"
			"In15.Cu" "In16.Cu"
		)
		(hatch none 0.5)
		(connect_pads
			(clearance 0)
		)
		(min_thickness 0.25)
		(keepout
			(tracks not_allowed)
			(vias allowed)
			(pads allowed)
			(copperpour not_allowed)
			(footprints allowed)
		)
		(placement
			(enabled no)
			(sheetname "")
		)
		(fill
			(thermal_gap 0.5)
			(thermal_bridge_width 0.5)
			(island_removal_mode 0)
		)
		(polygon
			(pts
				(arc
					(start 111.340646 -223.67367)
					(mid 111.36033 -223.62626)
					(end 111.367062 -223.575372)
				)
				(arc
					(start 111.367062 -223.575372)
					(mid 111.309406 -223.436178)
					(end 111.170212 -223.378522)
				)
				(arc
					(start 111.170212 -223.378522)
					(mid 111.071781 -223.404938)
					(end 110.999778 -223.477074)
				)
				(arc
					(start 110.530132 -224.291144)
					(mid 110.510448 -224.338554)
					(end 110.503716 -224.389442)
				)
				(arc
					(start 110.503716 -224.389442)
					(mid 110.561372 -224.528636)
					(end 110.700566 -224.586292)
				)
				(arc
					(start 110.700566 -224.586292)
					(mid 110.798997 -224.559876)
					(end 110.871 -224.48774)
				)
			)
		)
	)
	(zone
		(layers "F.Cu" "B.Cu" "In1.Cu" "In2.Cu" "In3.Cu" "In4.Cu" "In5.Cu" "In6.Cu"
			"In7.Cu" "In8.Cu" "In9.Cu" "In10.Cu" "In11.Cu" "In12.Cu" "In13.Cu" "In14.Cu"
			"In15.Cu" "In16.Cu"
		)
		(hatch none 0.5)
		(connect_pads
			(clearance 0)
		)
		(min_thickness 0.25)
		(keepout
			(tracks not_allowed)
			(vias allowed)
			(pads allowed)
			(copperpour not_allowed)
			(footprints allowed)
		)
		(placement
			(enabled no)
			(sheetname "")
		)
		(fill
			(thermal_gap 0.5)
			(thermal_bridge_width 0.5)
			(island_removal_mode 0)
		)
		(polygon
			(pts
				(arc
					(start 347.772228 -285.563056)
					(mid 347.752544 -285.610466)
					(end 347.745812 -285.661354)
				)
				(arc
					(start 347.745812 -285.661354)
					(mid 347.803468 -285.800548)
					(end 347.942662 -285.858204)
				)
				(arc
					(start 347.942662 -285.858204)
					(mid 348.041093 -285.831788)
					(end 348.113096 -285.759652)
				)
				(arc
					(start 348.582996 -284.945582)
					(mid 348.60268 -284.898172)
					(end 348.609412 -284.847284)
				)
				(arc
					(start 348.609412 -284.847284)
					(mid 348.551756 -284.70809)
					(end 348.412562 -284.650434)
				)
				(arc
					(start 348.412562 -284.650434)
					(mid 348.314131 -284.67685)
					(end 348.242128 -284.748986)
				)
			)
		)
	)
	(zone
		(layers "F.Cu" "B.Cu" "In1.Cu" "In2.Cu" "In3.Cu" "In4.Cu" "In5.Cu" "In6.Cu"
			"In7.Cu" "In8.Cu" "In9.Cu" "In10.Cu" "In11.Cu" "In12.Cu" "In13.Cu" "In14.Cu"
			"In15.Cu" "In16.Cu"
		)
		(hatch none 0.5)
		(connect_pads
			(clearance 0)
		)
		(min_thickness 0.25)
		(keepout
			(tracks not_allowed)
			(vias allowed)
			(pads allowed)
			(copperpour not_allowed)
			(footprints allowed)
		)
		(placement
			(enabled no)
			(sheetname "")
		)
		(fill
			(thermal_gap 0.5)
			(thermal_bridge_width 0.5)
			(island_removal_mode 0)
		)
		(polygon
			(pts
				(arc
					(start 101.083618 -283.219906)
					(mid 101.741478 -283.219906)
					(end 101.083618 -283.219906)
				)
			)
		)
	)
	(zone
		(layers "F.Cu" "B.Cu" "In1.Cu" "In2.Cu" "In3.Cu" "In4.Cu" "In5.Cu" "In6.Cu"
			"In7.Cu" "In8.Cu" "In9.Cu" "In10.Cu" "In11.Cu" "In12.Cu" "In13.Cu" "In14.Cu"
			"In15.Cu" "In16.Cu"
		)
		(hatch none 0.5)
		(connect_pads
			(clearance 0)
		)
		(min_thickness 0.25)
		(keepout
			(tracks not_allowed)
			(vias allowed)
			(pads allowed)
			(copperpour not_allowed)
			(footprints allowed)
		)
		(placement
			(enabled no)
			(sheetname "")
		)
		(fill
			(thermal_gap 0.5)
			(thermal_bridge_width 0.5)
			(island_removal_mode 0)
		)
		(polygon
			(pts
				(arc
					(start 92.155264 -285.661354)
					(mid 92.813124 -285.661354)
					(end 92.155264 -285.661354)
				)
			)
		)
	)
	(zone
		(layers "F.Cu" "B.Cu" "In1.Cu" "In2.Cu" "In3.Cu" "In4.Cu" "In5.Cu" "In6.Cu"
			"In7.Cu" "In8.Cu" "In9.Cu" "In10.Cu" "In11.Cu" "In12.Cu" "In13.Cu" "In14.Cu"
			"In15.Cu" "In16.Cu"
		)
		(hatch none 0.5)
		(connect_pads
			(clearance 0)
		)
		(min_thickness 0.25)
		(keepout
			(tracks not_allowed)
			(vias allowed)
			(pads allowed)
			(copperpour not_allowed)
			(footprints allowed)
		)
		(placement
			(enabled no)
			(sheetname "")
		)
		(fill
			(thermal_gap 0.5)
			(thermal_bridge_width 0.5)
			(island_removal_mode 0)
		)
		(polygon
			(pts
				(arc
					(start 103.432864 -282.405836)
					(mid 104.090724 -282.405836)
					(end 103.432864 -282.405836)
				)
			)
		)
	)
	(zone
		(layers "F.Cu" "B.Cu" "In1.Cu" "In2.Cu" "In3.Cu" "In4.Cu" "In5.Cu" "In6.Cu"
			"In7.Cu" "In8.Cu" "In9.Cu" "In10.Cu" "In11.Cu" "In12.Cu" "In13.Cu" "In14.Cu"
			"In15.Cu" "In16.Cu"
		)
		(hatch none 0.5)
		(connect_pads
			(clearance 0)
		)
		(min_thickness 0.25)
		(keepout
			(tracks not_allowed)
			(vias allowed)
			(pads allowed)
			(copperpour not_allowed)
			(footprints allowed)
		)
		(placement
			(enabled no)
			(sheetname "")
		)
		(fill
			(thermal_gap 0.5)
			(thermal_bridge_width 0.5)
			(island_removal_mode 0)
		)
		(polygon
			(pts
				(arc
					(start 377.875546 -286.475424)
					(mid 377.217686 -286.475424)
					(end 377.875546 -286.475424)
				)
			)
		)
	)
	(zone
		(layers "F.Cu" "B.Cu" "In1.Cu" "In2.Cu" "In3.Cu" "In4.Cu" "In5.Cu" "In6.Cu"
			"In7.Cu" "In8.Cu" "In9.Cu" "In10.Cu" "In11.Cu" "In12.Cu" "In13.Cu" "In14.Cu"
			"In15.Cu" "In16.Cu"
		)
		(hatch none 0.5)
		(connect_pads
			(clearance 0)
		)
		(min_thickness 0.25)
		(keepout
			(tracks not_allowed)
			(vias allowed)
			(pads allowed)
			(copperpour not_allowed)
			(footprints allowed)
		)
		(placement
			(enabled no)
			(sheetname "")
		)
		(fill
			(thermal_gap 0.5)
			(thermal_bridge_width 0.5)
			(island_removal_mode 0)
		)
		(polygon
			(pts
				(arc
					(start 377.54941 -400.477228)
					(mid 377.16841 -400.858228)
					(end 377.54941 -401.239228)
				)
				(arc
					(start 378.41301 -401.239228)
					(mid 378.79401 -400.858228)
					(end 378.41301 -400.477228)
				)
			)
		)
	)
	(zone
		(layers "F.Cu" "B.Cu" "In1.Cu" "In2.Cu" "In3.Cu" "In4.Cu" "In5.Cu" "In6.Cu"
			"In7.Cu" "In8.Cu" "In9.Cu" "In10.Cu" "In11.Cu" "In12.Cu" "In13.Cu" "In14.Cu"
			"In15.Cu" "In16.Cu"
		)
		(hatch none 0.5)
		(connect_pads
			(clearance 0)
		)
		(min_thickness 0.25)
		(keepout
			(tracks not_allowed)
			(vias allowed)
			(pads allowed)
			(copperpour not_allowed)
			(footprints allowed)
		)
		(placement
			(enabled no)
			(sheetname "")
		)
		(fill
			(thermal_gap 0.5)
			(thermal_bridge_width 0.5)
			(island_removal_mode 0)
		)
		(polygon
			(pts
				(arc
					(start 95.13316 -282.307538)
					(mid 95.113476 -282.354948)
					(end 95.106744 -282.405836)
				)
				(arc
					(start 95.106744 -282.405836)
					(mid 95.1644 -282.54503)
					(end 95.303594 -282.602686)
				)
				(arc
					(start 95.303594 -282.602686)
					(mid 95.402025 -282.57627)
					(end 95.474028 -282.504134)
				)
				(arc
					(start 95.943928 -281.690064)
					(mid 95.963612 -281.642654)
					(end 95.970344 -281.591766)
				)
				(arc
					(start 95.970344 -281.591766)
					(mid 95.912688 -281.452572)
					(end 95.773494 -281.394916)
				)
				(arc
					(start 95.773494 -281.394916)
					(mid 95.675063 -281.421332)
					(end 95.60306 -281.493468)
				)
			)
		)
	)
	(zone
		(layers "F.Cu" "B.Cu" "In1.Cu" "In2.Cu" "In3.Cu" "In4.Cu" "In5.Cu" "In6.Cu"
			"In7.Cu" "In8.Cu" "In9.Cu" "In10.Cu" "In11.Cu" "In12.Cu" "In13.Cu" "In14.Cu"
			"In15.Cu" "In16.Cu"
		)
		(hatch none 0.5)
		(connect_pads
			(clearance 0)
		)
		(min_thickness 0.25)
		(keepout
			(tracks not_allowed)
			(vias allowed)
			(pads allowed)
			(copperpour not_allowed)
			(footprints allowed)
		)
		(placement
			(enabled no)
			(sheetname "")
		)
		(fill
			(thermal_gap 0.5)
			(thermal_bridge_width 0.5)
			(island_removal_mode 0)
		)
		(polygon
			(pts
				(arc
					(start 366.01781 -221.94774)
					(mid 365.35995 -221.94774)
					(end 366.01781 -221.94774)
				)
			)
		)
	)
	(zone
		(layers "F.Cu" "B.Cu" "In1.Cu" "In2.Cu" "In3.Cu" "In4.Cu" "In5.Cu" "In6.Cu"
			"In7.Cu" "In8.Cu" "In9.Cu" "In10.Cu" "In11.Cu" "In12.Cu" "In13.Cu" "In14.Cu"
			"In15.Cu" "In16.Cu"
		)
		(hatch none 0.5)
		(connect_pads
			(clearance 0)
		)
		(min_thickness 0.25)
		(keepout
			(tracks not_allowed)
			(vias allowed)
			(pads allowed)
			(copperpour not_allowed)
			(footprints allowed)
		)
		(placement
			(enabled no)
			(sheetname "")
		)
		(fill
			(thermal_gap 0.5)
			(thermal_bridge_width 0.5)
			(island_removal_mode 0)
		)
		(polygon
			(pts
				(arc
					(start 237.247938 -115.915948)
					(mid 236.866938 -116.296948)
					(end 237.247938 -116.677948)
				)
				(arc
					(start 238.111538 -116.677948)
					(mid 238.492538 -116.296948)
					(end 238.111538 -115.915948)
				)
			)
		)
	)
	(zone
		(layers "F.Cu" "B.Cu" "In1.Cu" "In2.Cu" "In3.Cu" "In4.Cu" "In5.Cu" "In6.Cu"
			"In7.Cu" "In8.Cu" "In9.Cu" "In10.Cu" "In11.Cu" "In12.Cu" "In13.Cu" "In14.Cu"
			"In15.Cu" "In16.Cu"
		)
		(hatch none 0.5)
		(connect_pads
			(clearance 0)
		)
		(min_thickness 0.25)
		(keepout
			(tracks not_allowed)
			(vias allowed)
			(pads allowed)
			(copperpour not_allowed)
			(footprints allowed)
		)
		(placement
			(enabled no)
			(sheetname "")
		)
		(fill
			(thermal_gap 0.5)
			(thermal_bridge_width 0.5)
			(island_removal_mode 0)
		)
		(polygon
			(pts
				(arc
					(start 338.597748 -213.646766)
					(mid 338.53004 -213.574915)
					(end 338.434934 -213.548468)
				)
				(arc
					(start 338.434934 -213.548468)
					(mid 338.30472 -213.602404)
					(end 338.250784 -213.732618)
				)
				(arc
					(start 338.250784 -213.732618)
					(mid 338.256235 -213.776839)
					(end 338.27212 -213.81847)
				)
				(arc
					(start 338.741512 -214.708486)
					(mid 338.80922 -214.780337)
					(end 338.904326 -214.806784)
				)
				(arc
					(start 338.904326 -214.806784)
					(mid 339.03454 -214.752848)
					(end 339.088476 -214.622634)
				)
				(arc
					(start 339.088476 -214.622634)
					(mid 339.083025 -214.578413)
					(end 339.06714 -214.536782)
				)
			)
		)
	)
	(zone
		(layers "F.Cu" "B.Cu" "In1.Cu" "In2.Cu" "In3.Cu" "In4.Cu" "In5.Cu" "In6.Cu"
			"In7.Cu" "In8.Cu" "In9.Cu" "In10.Cu" "In11.Cu" "In12.Cu" "In13.Cu" "In14.Cu"
			"In15.Cu" "In16.Cu"
		)
		(hatch none 0.5)
		(connect_pads
			(clearance 0)
		)
		(min_thickness 0.25)
		(keepout
			(tracks not_allowed)
			(vias allowed)
			(pads allowed)
			(copperpour not_allowed)
			(footprints allowed)
		)
		(placement
			(enabled no)
			(sheetname "")
		)
		(fill
			(thermal_gap 0.5)
			(thermal_bridge_width 0.5)
			(island_removal_mode 0)
		)
		(polygon
			(pts
				(arc
					(start 102.962964 -289.807142)
					(mid 103.620824 -289.807142)
					(end 102.962964 -289.807142)
				)
			)
		)
	)
	(zone
		(layers "F.Cu" "B.Cu" "In1.Cu" "In2.Cu" "In3.Cu" "In4.Cu" "In5.Cu" "In6.Cu"
			"In7.Cu" "In8.Cu" "In9.Cu" "In10.Cu" "In11.Cu" "In12.Cu" "In13.Cu" "In14.Cu"
			"In15.Cu" "In16.Cu"
		)
		(hatch none 0.5)
		(connect_pads
			(clearance 0)
		)
		(min_thickness 0.25)
		(keepout
			(tracks not_allowed)
			(vias allowed)
			(pads allowed)
			(copperpour not_allowed)
			(footprints allowed)
		)
		(placement
			(enabled no)
			(sheetname "")
		)
		(fill
			(thermal_gap 0.5)
			(thermal_bridge_width 0.5)
			(island_removal_mode 0)
		)
		(polygon
			(pts
				(arc
					(start 135.464042 -214.546434)
					(mid 134.806182 -214.546434)
					(end 135.464042 -214.546434)
				)
			)
		)
	)
	(zone
		(layers "F.Cu" "B.Cu" "In1.Cu" "In2.Cu" "In3.Cu" "In4.Cu" "In5.Cu" "In6.Cu"
			"In7.Cu" "In8.Cu" "In9.Cu" "In10.Cu" "In11.Cu" "In12.Cu" "In13.Cu" "In14.Cu"
			"In15.Cu" "In16.Cu"
		)
		(hatch none 0.5)
		(connect_pads
			(clearance 0)
		)
		(min_thickness 0.25)
		(keepout
			(tracks not_allowed)
			(vias allowed)
			(pads allowed)
			(copperpour not_allowed)
			(footprints allowed)
		)
		(placement
			(enabled no)
			(sheetname "")
		)
		(fill
			(thermal_gap 0.5)
			(thermal_bridge_width 0.5)
			(island_removal_mode 0)
		)
		(polygon
			(pts
				(arc
					(start 95.303848 -280.581354)
					(mid 95.106998 -280.778204)
					(end 95.303848 -280.975054)
				)
				(arc
					(start 96.243648 -280.975054)
					(mid 96.440498 -280.778204)
					(end 96.243648 -280.581354)
				)
			)
		)
	)
	(zone
		(layers "F.Cu" "B.Cu" "In1.Cu" "In2.Cu" "In3.Cu" "In4.Cu" "In5.Cu" "In6.Cu"
			"In7.Cu" "In8.Cu" "In9.Cu" "In10.Cu" "In11.Cu" "In12.Cu" "In13.Cu" "In14.Cu"
			"In15.Cu" "In16.Cu"
		)
		(hatch none 0.5)
		(connect_pads
			(clearance 0)
		)
		(min_thickness 0.25)
		(keepout
			(tracks not_allowed)
			(vias allowed)
			(pads allowed)
			(copperpour not_allowed)
			(footprints allowed)
		)
		(placement
			(enabled no)
			(sheetname "")
		)
		(fill
			(thermal_gap 0.5)
			(thermal_bridge_width 0.5)
			(island_removal_mode 0)
		)
		(polygon
			(pts
				(arc
					(start 132.174996 -213.732618)
					(mid 131.517136 -213.732618)
					(end 132.174996 -213.732618)
				)
			)
		)
	)
	(zone
		(layers "F.Cu" "B.Cu" "In1.Cu" "In2.Cu" "In3.Cu" "In4.Cu" "In5.Cu" "In6.Cu"
			"In7.Cu" "In8.Cu" "In9.Cu" "In10.Cu" "In11.Cu" "In12.Cu" "In13.Cu" "In14.Cu"
			"In15.Cu" "In16.Cu"
		)
		(hatch none 0.5)
		(connect_pads
			(clearance 0)
		)
		(min_thickness 0.25)
		(keepout
			(tracks not_allowed)
			(vias allowed)
			(pads allowed)
			(copperpour not_allowed)
			(footprints allowed)
		)
		(placement
			(enabled no)
			(sheetname "")
		)
		(fill
			(thermal_gap 0.5)
			(thermal_bridge_width 0.5)
			(island_removal_mode 0)
		)
		(polygon
			(pts
				(arc
					(start 344.872564 -217.878406)
					(mid 344.214704 -217.878406)
					(end 344.872564 -217.878406)
				)
			)
		)
	)
	(zone
		(layers "F.Cu" "B.Cu" "In1.Cu" "In2.Cu" "In3.Cu" "In4.Cu" "In5.Cu" "In6.Cu"
			"In7.Cu" "In8.Cu" "In9.Cu" "In10.Cu" "In11.Cu" "In12.Cu" "In13.Cu" "In14.Cu"
			"In15.Cu" "In16.Cu"
		)
		(hatch none 0.5)
		(connect_pads
			(clearance 0)
		)
		(min_thickness 0.25)
		(keepout
			(tracks not_allowed)
			(vias allowed)
			(pads allowed)
			(copperpour not_allowed)
			(footprints allowed)
		)
		(placement
			(enabled no)
			(sheetname "")
		)
		(fill
			(thermal_gap 0.5)
			(thermal_bridge_width 0.5)
			(island_removal_mode 0)
		)
		(polygon
			(pts
				(arc
					(start 351.450656 -214.622634)
					(mid 350.792796 -214.622634)
					(end 351.450656 -214.622634)
				)
			)
		)
	)
	(zone
		(layers "F.Cu" "B.Cu" "In1.Cu" "In2.Cu" "In3.Cu" "In4.Cu" "In5.Cu" "In6.Cu"
			"In7.Cu" "In8.Cu" "In9.Cu" "In10.Cu" "In11.Cu" "In12.Cu" "In13.Cu" "In14.Cu"
			"In15.Cu" "In16.Cu"
		)
		(hatch none 0.5)
		(connect_pads
			(clearance 0)
		)
		(min_thickness 0.25)
		(keepout
			(tracks not_allowed)
			(vias allowed)
			(pads allowed)
			(copperpour not_allowed)
			(footprints allowed)
		)
		(placement
			(enabled no)
			(sheetname "")
		)
		(fill
			(thermal_gap 0.5)
			(thermal_bridge_width 0.5)
			(island_removal_mode 0)
		)
		(polygon
			(pts
				(arc
					(start 122.776996 -213.732618)
					(mid 122.119136 -213.732618)
					(end 122.776996 -213.732618)
				)
			)
		)
	)
	(zone
		(layers "F.Cu" "B.Cu" "In1.Cu" "In2.Cu" "In3.Cu" "In4.Cu" "In5.Cu" "In6.Cu"
			"In7.Cu" "In8.Cu" "In9.Cu" "In10.Cu" "In11.Cu" "In12.Cu" "In13.Cu" "In14.Cu"
			"In15.Cu" "In16.Cu"
		)
		(hatch none 0.5)
		(connect_pads
			(clearance 0)
		)
		(min_thickness 0.25)
		(keepout
			(tracks not_allowed)
			(vias allowed)
			(pads allowed)
			(copperpour not_allowed)
			(footprints allowed)
		)
		(placement
			(enabled no)
			(sheetname "")
		)
		(fill
			(thermal_gap 0.5)
			(thermal_bridge_width 0.5)
			(island_removal_mode 0)
		)
		(polygon
			(pts
				(xy 849.322152 -394.78585) (xy 849.322152 -404.78583) (xy 849.017352 -404.48103) (xy 849.017352 -395.09065)
			)
		)
	)
	(zone
		(layers "F.Cu" "B.Cu" "In1.Cu" "In2.Cu" "In3.Cu" "In4.Cu" "In5.Cu" "In6.Cu"
			"In7.Cu" "In8.Cu" "In9.Cu" "In10.Cu" "In11.Cu" "In12.Cu" "In13.Cu" "In14.Cu"
			"In15.Cu" "In16.Cu"
		)
		(hatch none 0.5)
		(connect_pads
			(clearance 0)
		)
		(min_thickness 0.25)
		(keepout
			(tracks not_allowed)
			(vias allowed)
			(pads allowed)
			(copperpour not_allowed)
			(footprints allowed)
		)
		(placement
			(enabled no)
			(sheetname "")
		)
		(fill
			(thermal_gap 0.5)
			(thermal_bridge_width 0.5)
			(island_removal_mode 0)
		)
		(polygon
			(pts
				(arc
					(start 236.405674 -134.360666)
					(mid 236.024674 -134.741666)
					(end 236.405674 -135.122666)
				)
				(arc
					(start 237.178342 -135.122666)
					(mid 237.559342 -134.741666)
					(end 237.178342 -134.360666)
				)
			)
		)
	)
	(zone
		(layers "F.Cu" "B.Cu" "In1.Cu" "In2.Cu" "In3.Cu" "In4.Cu" "In5.Cu" "In6.Cu"
			"In7.Cu" "In8.Cu" "In9.Cu" "In10.Cu" "In11.Cu" "In12.Cu" "In13.Cu" "In14.Cu"
			"In15.Cu" "In16.Cu"
		)
		(hatch none 0.5)
		(connect_pads
			(clearance 0)
		)
		(min_thickness 0.25)
		(keepout
			(tracks not_allowed)
			(vias allowed)
			(pads allowed)
			(copperpour not_allowed)
			(footprints allowed)
		)
		(placement
			(enabled no)
			(sheetname "")
		)
		(fill
			(thermal_gap 0.5)
			(thermal_bridge_width 0.5)
			(island_removal_mode 0)
		)
		(polygon
			(pts
				(arc
					(start 373.176546 -288.103056)
					(mid 372.518686 -288.103056)
					(end 373.176546 -288.103056)
				)
			)
		)
	)
	(zone
		(layers "F.Cu" "B.Cu" "In1.Cu" "In2.Cu" "In3.Cu" "In4.Cu" "In5.Cu" "In6.Cu"
			"In7.Cu" "In8.Cu" "In9.Cu" "In10.Cu" "In11.Cu" "In12.Cu" "In13.Cu" "In14.Cu"
			"In15.Cu" "In16.Cu"
		)
		(hatch none 0.5)
		(connect_pads
			(clearance 0)
		)
		(min_thickness 0.25)
		(keepout
			(tracks not_allowed)
			(vias allowed)
			(pads allowed)
			(copperpour not_allowed)
			(footprints allowed)
		)
		(placement
			(enabled no)
			(sheetname "")
		)
		(fill
			(thermal_gap 0.5)
			(thermal_bridge_width 0.5)
			(island_removal_mode 0)
		)
		(polygon
			(pts
				(arc
					(start 231.034336 -115.98529)
					(mid 230.653336 -116.36629)
					(end 231.034336 -116.74729)
				)
				(arc
					(start 231.897936 -116.74729)
					(mid 232.278936 -116.36629)
					(end 231.897936 -115.98529)
				)
			)
		)
	)
	(zone
		(layers "F.Cu" "B.Cu" "In1.Cu" "In2.Cu" "In3.Cu" "In4.Cu" "In5.Cu" "In6.Cu"
			"In7.Cu" "In8.Cu" "In9.Cu" "In10.Cu" "In11.Cu" "In12.Cu" "In13.Cu" "In14.Cu"
			"In15.Cu" "In16.Cu"
		)
		(hatch none 0.5)
		(connect_pads
			(clearance 0)
		)
		(min_thickness 0.25)
		(keepout
			(tracks not_allowed)
			(vias allowed)
			(pads allowed)
			(copperpour not_allowed)
			(footprints allowed)
		)
		(placement
			(enabled no)
			(sheetname "")
		)
		(fill
			(thermal_gap 0.5)
			(thermal_bridge_width 0.5)
			(island_removal_mode 0)
		)
		(polygon
			(pts
				(arc
					(start 126.480062 -289.003232)
					(mid 126.495986 -288.961481)
					(end 126.501398 -288.917126)
				)
				(arc
					(start 126.501398 -288.917126)
					(mid 126.447462 -288.786912)
					(end 126.317248 -288.732976)
				)
				(arc
					(start 126.317248 -288.732976)
					(mid 126.222228 -288.759384)
					(end 126.154434 -288.83102)
				)
				(arc
					(start 125.68428 -289.721036)
					(mid 125.668356 -289.762787)
					(end 125.662944 -289.807142)
				)
				(arc
					(start 125.662944 -289.807142)
					(mid 125.71688 -289.937356)
					(end 125.847094 -289.991292)
				)
				(arc
					(start 125.847094 -289.991292)
					(mid 125.942114 -289.964884)
					(end 126.009908 -289.893248)
				)
			)
		)
	)
	(zone
		(layers "F.Cu" "B.Cu" "In1.Cu" "In2.Cu" "In3.Cu" "In4.Cu" "In5.Cu" "In6.Cu"
			"In7.Cu" "In8.Cu" "In9.Cu" "In10.Cu" "In11.Cu" "In12.Cu" "In13.Cu" "In14.Cu"
			"In15.Cu" "In16.Cu"
		)
		(hatch none 0.5)
		(connect_pads
			(clearance 0)
		)
		(min_thickness 0.25)
		(keepout
			(tracks not_allowed)
			(vias allowed)
			(pads allowed)
			(copperpour not_allowed)
			(footprints allowed)
		)
		(placement
			(enabled no)
			(sheetname "")
		)
		(fill
			(thermal_gap 0.5)
			(thermal_bridge_width 0.5)
			(island_removal_mode 0)
		)
		(polygon
			(pts
				(arc
					(start 92.703396 -213.732618)
					(mid 92.045536 -213.732618)
					(end 92.703396 -213.732618)
				)
			)
		)
	)
	(zone
		(layers "F.Cu" "B.Cu" "In1.Cu" "In2.Cu" "In3.Cu" "In4.Cu" "In5.Cu" "In6.Cu"
			"In7.Cu" "In8.Cu" "In9.Cu" "In10.Cu" "In11.Cu" "In12.Cu" "In13.Cu" "In14.Cu"
			"In15.Cu" "In16.Cu"
		)
		(hatch none 0.5)
		(connect_pads
			(clearance 0)
		)
		(min_thickness 0.25)
		(keepout
			(tracks not_allowed)
			(vias allowed)
			(pads allowed)
			(copperpour not_allowed)
			(footprints allowed)
		)
		(placement
			(enabled no)
			(sheetname "")
		)
		(fill
			(thermal_gap 0.5)
			(thermal_bridge_width 0.5)
			(island_removal_mode 0)
		)
		(polygon
			(pts
				(arc
					(start 365.389668 -224.291144)
					(mid 365.317679 -224.218985)
					(end 365.219234 -224.192592)
				)
				(arc
					(start 365.219234 -224.192592)
					(mid 365.08004 -224.250248)
					(end 365.022384 -224.389442)
				)
				(arc
					(start 365.022384 -224.389442)
					(mid 365.029141 -224.440323)
					(end 365.0488 -224.48774)
				)
				(arc
					(start 365.518446 -225.301556)
					(mid 365.590435 -225.373715)
					(end 365.68888 -225.400108)
				)
				(arc
					(start 365.68888 -225.400108)
					(mid 365.828074 -225.342452)
					(end 365.88573 -225.203258)
				)
				(arc
					(start 365.88573 -225.203258)
					(mid 365.878973 -225.152377)
					(end 365.859314 -225.10496)
				)
			)
		)
	)
	(zone
		(layers "F.Cu" "B.Cu" "In1.Cu" "In2.Cu" "In3.Cu" "In4.Cu" "In5.Cu" "In6.Cu"
			"In7.Cu" "In8.Cu" "In9.Cu" "In10.Cu" "In11.Cu" "In12.Cu" "In13.Cu" "In14.Cu"
			"In15.Cu" "In16.Cu"
		)
		(hatch none 0.5)
		(connect_pads
			(clearance 0)
		)
		(min_thickness 0.25)
		(keepout
			(tracks not_allowed)
			(vias allowed)
			(pads allowed)
			(copperpour not_allowed)
			(footprints allowed)
		)
		(placement
			(enabled no)
			(sheetname "")
		)
		(fill
			(thermal_gap 0.5)
			(thermal_bridge_width 0.5)
			(island_removal_mode 0)
		)
		(polygon
			(pts
				(arc
					(start 378.89561 -406.62352)
					(mid 378.51461 -407.00452)
					(end 378.89561 -407.38552)
				)
				(arc
					(start 379.75921 -407.38552)
					(mid 380.14021 -407.00452)
					(end 379.75921 -406.62352)
				)
			)
		)
	)
	(zone
		(layers "F.Cu" "B.Cu" "In1.Cu" "In2.Cu" "In3.Cu" "In4.Cu" "In5.Cu" "In6.Cu"
			"In7.Cu" "In8.Cu" "In9.Cu" "In10.Cu" "In11.Cu" "In12.Cu" "In13.Cu" "In14.Cu"
			"In15.Cu" "In16.Cu"
		)
		(hatch none 0.5)
		(connect_pads
			(clearance 0)
		)
		(min_thickness 0.25)
		(keepout
			(tracks not_allowed)
			(vias allowed)
			(pads allowed)
			(copperpour not_allowed)
			(footprints allowed)
		)
		(placement
			(enabled no)
			(sheetname "")
		)
		(fill
			(thermal_gap 0.5)
			(thermal_bridge_width 0.5)
			(island_removal_mode 0)
		)
		(polygon
			(pts
				(arc
					(start 131.705096 -217.878406)
					(mid 131.047236 -217.878406)
					(end 131.705096 -217.878406)
				)
			)
		)
	)
	(zone
		(layers "F.Cu" "B.Cu" "In1.Cu" "In2.Cu" "In3.Cu" "In4.Cu" "In5.Cu" "In6.Cu"
			"In7.Cu" "In8.Cu" "In9.Cu" "In10.Cu" "In11.Cu" "In12.Cu" "In13.Cu" "In14.Cu"
			"In15.Cu" "In16.Cu"
		)
		(hatch none 0.5)
		(connect_pads
			(clearance 0)
		)
		(min_thickness 0.25)
		(keepout
			(tracks not_allowed)
			(vias allowed)
			(pads allowed)
			(copperpour not_allowed)
			(footprints allowed)
		)
		(placement
			(enabled no)
			(sheetname "")
		)
		(fill
			(thermal_gap 0.5)
			(thermal_bridge_width 0.5)
			(island_removal_mode 0)
		)
		(polygon
			(pts
				(arc
					(start 96.414082 -282.307538)
					(mid 96.342093 -282.235379)
					(end 96.243648 -282.208986)
				)
				(arc
					(start 96.243648 -282.208986)
					(mid 96.104454 -282.266642)
					(end 96.046798 -282.405836)
				)
				(arc
					(start 96.046798 -282.405836)
					(mid 96.053555 -282.456717)
					(end 96.073214 -282.504134)
				)
				(arc
					(start 96.543114 -283.318204)
					(mid 96.615103 -283.390363)
					(end 96.713548 -283.416756)
				)
				(arc
					(start 96.713548 -283.416756)
					(mid 96.852742 -283.3591)
					(end 96.910398 -283.219906)
				)
				(arc
					(start 96.910398 -283.219906)
					(mid 96.903641 -283.169025)
					(end 96.883982 -283.121608)
				)
			)
		)
	)
	(zone
		(layers "F.Cu" "B.Cu" "In1.Cu" "In2.Cu" "In3.Cu" "In4.Cu" "In5.Cu" "In6.Cu"
			"In7.Cu" "In8.Cu" "In9.Cu" "In10.Cu" "In11.Cu" "In12.Cu" "In13.Cu" "In14.Cu"
			"In15.Cu" "In16.Cu"
		)
		(hatch none 0.5)
		(connect_pads
			(clearance 0)
		)
		(min_thickness 0.25)
		(keepout
			(tracks not_allowed)
			(vias allowed)
			(pads allowed)
			(copperpour not_allowed)
			(footprints allowed)
		)
		(placement
			(enabled no)
			(sheetname "")
		)
		(fill
			(thermal_gap 0.5)
			(thermal_bridge_width 0.5)
			(island_removal_mode 0)
		)
		(polygon
			(pts
				(arc
					(start 116.198142 -221.94774)
					(mid 115.540282 -221.94774)
					(end 116.198142 -221.94774)
				)
			)
		)
	)
	(zone
		(layers "F.Cu" "B.Cu" "In1.Cu" "In2.Cu" "In3.Cu" "In4.Cu" "In5.Cu" "In6.Cu"
			"In7.Cu" "In8.Cu" "In9.Cu" "In10.Cu" "In11.Cu" "In12.Cu" "In13.Cu" "In14.Cu"
			"In15.Cu" "In16.Cu"
		)
		(hatch none 0.5)
		(connect_pads
			(clearance 0)
		)
		(min_thickness 0.25)
		(keepout
			(tracks not_allowed)
			(vias allowed)
			(pads allowed)
			(copperpour not_allowed)
			(footprints allowed)
		)
		(placement
			(enabled no)
			(sheetname "")
		)
		(fill
			(thermal_gap 0.5)
			(thermal_bridge_width 0.5)
			(island_removal_mode 0)
		)
		(polygon
			(pts
				(arc
					(start 374.48617 -403.502876)
					(mid 374.10517 -403.883876)
					(end 374.48617 -404.264876)
				)
				(arc
					(start 375.34977 -404.264876)
					(mid 375.73077 -403.883876)
					(end 375.34977 -403.502876)
				)
			)
		)
	)
	(zone
		(layers "F.Cu" "B.Cu" "In1.Cu" "In2.Cu" "In3.Cu" "In4.Cu" "In5.Cu" "In6.Cu"
			"In7.Cu" "In8.Cu" "In9.Cu" "In10.Cu" "In11.Cu" "In12.Cu" "In13.Cu" "In14.Cu"
			"In15.Cu" "In16.Cu"
		)
		(hatch none 0.5)
		(connect_pads
			(clearance 0)
		)
		(min_thickness 0.25)
		(keepout
			(tracks not_allowed)
			(vias allowed)
			(pads allowed)
			(copperpour not_allowed)
			(footprints allowed)
		)
		(placement
			(enabled no)
			(sheetname "")
		)
		(fill
			(thermal_gap 0.5)
			(thermal_bridge_width 0.5)
			(island_removal_mode 0)
		)
		(polygon
			(pts
				(arc
					(start 131.626864 -285.661354)
					(mid 132.284724 -285.661354)
					(end 131.626864 -285.661354)
				)
			)
		)
	)
	(zone
		(layers "F.Cu" "B.Cu" "In1.Cu" "In2.Cu" "In3.Cu" "In4.Cu" "In5.Cu" "In6.Cu"
			"In7.Cu" "In8.Cu" "In9.Cu" "In10.Cu" "In11.Cu" "In12.Cu" "In13.Cu" "In14.Cu"
			"In15.Cu" "In16.Cu"
		)
		(hatch none 0.5)
		(connect_pads
			(clearance 0)
		)
		(min_thickness 0.25)
		(keepout
			(tracks not_allowed)
			(vias allowed)
			(pads allowed)
			(copperpour not_allowed)
			(footprints allowed)
		)
		(placement
			(enabled no)
			(sheetname "")
		)
		(fill
			(thermal_gap 0.5)
			(thermal_bridge_width 0.5)
			(island_removal_mode 0)
		)
		(polygon
			(pts
				(arc
					(start 111.029496 -221.133924)
					(mid 110.371636 -221.133924)
					(end 111.029496 -221.133924)
				)
			)
		)
	)
	(zone
		(layers "F.Cu" "B.Cu" "In1.Cu" "In2.Cu" "In3.Cu" "In4.Cu" "In5.Cu" "In6.Cu"
			"In7.Cu" "In8.Cu" "In9.Cu" "In10.Cu" "In11.Cu" "In12.Cu" "In13.Cu" "In14.Cu"
			"In15.Cu" "In16.Cu"
		)
		(hatch none 0.5)
		(connect_pads
			(clearance 0)
		)
		(min_thickness 0.25)
		(keepout
			(tracks not_allowed)
			(vias allowed)
			(pads allowed)
			(copperpour not_allowed)
			(footprints allowed)
		)
		(placement
			(enabled no)
			(sheetname "")
		)
		(fill
			(thermal_gap 0.5)
			(thermal_bridge_width 0.5)
			(island_removal_mode 0)
		)
		(polygon
			(pts
				(arc
					(start 343.073228 -282.307538)
					(mid 343.053544 -282.354948)
					(end 343.046812 -282.405836)
				)
				(arc
					(start 343.046812 -282.405836)
					(mid 343.104468 -282.54503)
					(end 343.243662 -282.602686)
				)
				(arc
					(start 343.243662 -282.602686)
					(mid 343.342093 -282.57627)
					(end 343.414096 -282.504134)
				)
				(arc
					(start 343.883996 -281.690064)
					(mid 343.90368 -281.642654)
					(end 343.910412 -281.591766)
				)
				(arc
					(start 343.910412 -281.591766)
					(mid 343.852756 -281.452572)
					(end 343.713562 -281.394916)
				)
				(arc
					(start 343.713562 -281.394916)
					(mid 343.615131 -281.421332)
					(end 343.543128 -281.493468)
				)
			)
		)
	)
	(zone
		(layers "F.Cu" "B.Cu" "In1.Cu" "In2.Cu" "In3.Cu" "In4.Cu" "In5.Cu" "In6.Cu"
			"In7.Cu" "In8.Cu" "In9.Cu" "In10.Cu" "In11.Cu" "In12.Cu" "In13.Cu" "In14.Cu"
			"In15.Cu" "In16.Cu"
		)
		(hatch none 0.5)
		(connect_pads
			(clearance 0)
		)
		(min_thickness 0.25)
		(keepout
			(tracks not_allowed)
			(vias allowed)
			(pads allowed)
			(copperpour not_allowed)
			(footprints allowed)
		)
		(placement
			(enabled no)
			(sheetname "")
		)
		(fill
			(thermal_gap 0.5)
			(thermal_bridge_width 0.5)
			(island_removal_mode 0)
		)
		(polygon
			(pts
				(arc
					(start 97.402142 -221.94774)
					(mid 96.744282 -221.94774)
					(end 97.402142 -221.94774)
				)
			)
		)
	)
	(zone
		(layers "F.Cu" "B.Cu" "In1.Cu" "In2.Cu" "In3.Cu" "In4.Cu" "In5.Cu" "In6.Cu"
			"In7.Cu" "In8.Cu" "In9.Cu" "In10.Cu" "In11.Cu" "In12.Cu" "In13.Cu" "In14.Cu"
			"In15.Cu" "In16.Cu"
		)
		(hatch none 0.5)
		(connect_pads
			(clearance 0)
		)
		(min_thickness 0.25)
		(keepout
			(tracks not_allowed)
			(vias allowed)
			(pads allowed)
			(copperpour not_allowed)
			(footprints allowed)
		)
		(placement
			(enabled no)
			(sheetname "")
		)
		(fill
			(thermal_gap 0.5)
			(thermal_bridge_width 0.5)
			(island_removal_mode 0)
		)
		(polygon
			(pts
				(arc
					(start 124.564394 -409.649168)
					(mid 124.183394 -410.030168)
					(end 124.564394 -410.411168)
				)
				(arc
					(start 125.427994 -410.411168)
					(mid 125.808994 -410.030168)
					(end 125.427994 -409.649168)
				)
			)
		)
	)
	(zone
		(layers "F.Cu" "B.Cu" "In1.Cu" "In2.Cu" "In3.Cu" "In4.Cu" "In5.Cu" "In6.Cu"
			"In7.Cu" "In8.Cu" "In9.Cu" "In10.Cu" "In11.Cu" "In12.Cu" "In13.Cu" "In14.Cu"
			"In15.Cu" "In16.Cu"
		)
		(hatch none 0.5)
		(connect_pads
			(clearance 0)
		)
		(min_thickness 0.25)
		(keepout
			(tracks not_allowed)
			(vias allowed)
			(pads allowed)
			(copperpour not_allowed)
			(footprints allowed)
		)
		(placement
			(enabled no)
			(sheetname "")
		)
		(fill
			(thermal_gap 0.5)
			(thermal_bridge_width 0.5)
			(island_removal_mode 0)
		)
		(polygon
			(pts
				(arc
					(start 366.32896 -221.231968)
					(mid 366.348644 -221.184558)
					(end 366.355376 -221.13367)
				)
				(arc
					(start 366.355376 -221.13367)
					(mid 366.29772 -220.994476)
					(end 366.158526 -220.93682)
				)
				(arc
					(start 366.158526 -220.93682)
					(mid 366.060095 -220.963236)
					(end 365.988092 -221.035372)
				)
				(arc
					(start 365.518446 -221.849442)
					(mid 365.498762 -221.896852)
					(end 365.49203 -221.94774)
				)
				(arc
					(start 365.49203 -221.94774)
					(mid 365.549686 -222.086934)
					(end 365.68888 -222.14459)
				)
				(arc
					(start 365.68888 -222.14459)
					(mid 365.787311 -222.118174)
					(end 365.859314 -222.046038)
				)
			)
		)
	)
	(zone
		(layers "F.Cu" "B.Cu" "In1.Cu" "In2.Cu" "In3.Cu" "In4.Cu" "In5.Cu" "In6.Cu"
			"In7.Cu" "In8.Cu" "In9.Cu" "In10.Cu" "In11.Cu" "In12.Cu" "In13.Cu" "In14.Cu"
			"In15.Cu" "In16.Cu"
		)
		(hatch none 0.5)
		(connect_pads
			(clearance 0)
		)
		(min_thickness 0.25)
		(keepout
			(tracks not_allowed)
			(vias allowed)
			(pads allowed)
			(copperpour not_allowed)
			(footprints allowed)
		)
		(placement
			(enabled no)
			(sheetname "")
		)
		(fill
			(thermal_gap 0.5)
			(thermal_bridge_width 0.5)
			(island_removal_mode 0)
		)
		(polygon
			(pts
				(arc
					(start 370.558822 -220.22181)
					(mid 370.486833 -220.149651)
					(end 370.388388 -220.123258)
				)
				(arc
					(start 370.388388 -220.123258)
					(mid 370.249194 -220.180914)
					(end 370.191538 -220.320108)
				)
				(arc
					(start 370.191538 -220.320108)
					(mid 370.198295 -220.370989)
					(end 370.217954 -220.418406)
				)
				(arc
					(start 370.6876 -221.232222)
					(mid 370.759589 -221.304381)
					(end 370.858034 -221.330774)
				)
				(arc
					(start 370.858034 -221.330774)
					(mid 370.997228 -221.273118)
					(end 371.054884 -221.133924)
				)
				(arc
					(start 371.054884 -221.133924)
					(mid 371.048127 -221.083043)
					(end 371.028468 -221.035626)
				)
			)
		)
	)
	(zone
		(layers "F.Cu" "B.Cu" "In1.Cu" "In2.Cu" "In3.Cu" "In4.Cu" "In5.Cu" "In6.Cu"
			"In7.Cu" "In8.Cu" "In9.Cu" "In10.Cu" "In11.Cu" "In12.Cu" "In13.Cu" "In14.Cu"
			"In15.Cu" "In16.Cu"
		)
		(hatch none 0.5)
		(connect_pads
			(clearance 0)
		)
		(min_thickness 0.25)
		(keepout
			(tracks not_allowed)
			(vias allowed)
			(pads allowed)
			(copperpour not_allowed)
			(footprints allowed)
		)
		(placement
			(enabled no)
			(sheetname "")
		)
		(fill
			(thermal_gap 0.5)
			(thermal_bridge_width 0.5)
			(island_removal_mode 0)
		)
		(polygon
			(pts
				(arc
					(start 395.629384 -17.220438)
					(mid 395.248384 -17.601438)
					(end 395.629384 -17.982438)
				)
				(arc
					(start 396.492984 -17.982438)
					(mid 396.873984 -17.601438)
					(end 396.492984 -17.220438)
				)
			)
		)
	)
	(zone
		(layers "F.Cu" "B.Cu" "In1.Cu" "In2.Cu" "In3.Cu" "In4.Cu" "In5.Cu" "In6.Cu"
			"In7.Cu" "In8.Cu" "In9.Cu" "In10.Cu" "In11.Cu" "In12.Cu" "In13.Cu" "In14.Cu"
			"In15.Cu" "In16.Cu"
		)
		(hatch none 0.5)
		(connect_pads
			(clearance 0)
		)
		(min_thickness 0.25)
		(keepout
			(tracks not_allowed)
			(vias allowed)
			(pads allowed)
			(copperpour not_allowed)
			(footprints allowed)
		)
		(placement
			(enabled no)
			(sheetname "")
		)
		(fill
			(thermal_gap 0.5)
			(thermal_bridge_width 0.5)
			(island_removal_mode 0)
		)
		(polygon
			(pts
				(arc
					(start 142.943834 -409.649168)
					(mid 142.562834 -410.030168)
					(end 142.943834 -410.411168)
				)
				(arc
					(start 143.807434 -410.411168)
					(mid 144.188434 -410.030168)
					(end 143.807434 -409.649168)
				)
			)
		)
	)
	(zone
		(layers "F.Cu" "B.Cu" "In1.Cu" "In2.Cu" "In3.Cu" "In4.Cu" "In5.Cu" "In6.Cu"
			"In7.Cu" "In8.Cu" "In9.Cu" "In10.Cu" "In11.Cu" "In12.Cu" "In13.Cu" "In14.Cu"
			"In15.Cu" "In16.Cu"
		)
		(hatch none 0.5)
		(connect_pads
			(clearance 0)
		)
		(min_thickness 0.25)
		(keepout
			(tracks not_allowed)
			(vias allowed)
			(pads allowed)
			(copperpour not_allowed)
			(footprints allowed)
		)
		(placement
			(enabled no)
			(sheetname "")
		)
		(fill
			(thermal_gap 0.5)
			(thermal_bridge_width 0.5)
			(island_removal_mode 0)
		)
		(polygon
			(pts
				(arc
					(start 351.274888 -406.62352)
					(mid 350.893888 -407.00452)
					(end 351.274888 -407.38552)
				)
				(arc
					(start 352.138488 -407.38552)
					(mid 352.519488 -407.00452)
					(end 352.138488 -406.62352)
				)
			)
		)
	)
	(zone
		(layers "F.Cu" "B.Cu" "In1.Cu" "In2.Cu" "In3.Cu" "In4.Cu" "In5.Cu" "In6.Cu"
			"In7.Cu" "In8.Cu" "In9.Cu" "In10.Cu" "In11.Cu" "In12.Cu" "In13.Cu" "In14.Cu"
			"In15.Cu" "In16.Cu"
		)
		(hatch none 0.5)
		(connect_pads
			(clearance 0)
		)
		(min_thickness 0.25)
		(keepout
			(tracks not_allowed)
			(vias allowed)
			(pads allowed)
			(copperpour not_allowed)
			(footprints allowed)
		)
		(placement
			(enabled no)
			(sheetname "")
		)
		(fill
			(thermal_gap 0.5)
			(thermal_bridge_width 0.5)
			(island_removal_mode 0)
		)
		(polygon
			(pts
				(arc
					(start 356.826566 -46.421802)
					(mid 356.445566 -46.802802)
					(end 356.826566 -47.183802)
				)
				(arc
					(start 357.690166 -47.183802)
					(mid 358.071166 -46.802802)
					(end 357.690166 -46.421802)
				)
			)
		)
	)
	(zone
		(layers "F.Cu" "B.Cu" "In1.Cu" "In2.Cu" "In3.Cu" "In4.Cu" "In5.Cu" "In6.Cu"
			"In7.Cu" "In8.Cu" "In9.Cu" "In10.Cu" "In11.Cu" "In12.Cu" "In13.Cu" "In14.Cu"
			"In15.Cu" "In16.Cu"
		)
		(hatch none 0.5)
		(connect_pads
			(clearance 0)
		)
		(min_thickness 0.25)
		(keepout
			(tracks not_allowed)
			(vias allowed)
			(pads allowed)
			(copperpour not_allowed)
			(footprints allowed)
		)
		(placement
			(enabled no)
			(sheetname "")
		)
		(fill
			(thermal_gap 0.5)
			(thermal_bridge_width 0.5)
			(island_removal_mode 0)
		)
		(polygon
			(pts
				(arc
					(start 368.678714 -223.67367)
					(mid 368.698398 -223.62626)
					(end 368.70513 -223.575372)
				)
				(arc
					(start 368.70513 -223.575372)
					(mid 368.647474 -223.436178)
					(end 368.50828 -223.378522)
				)
				(arc
					(start 368.50828 -223.378522)
					(mid 368.409849 -223.404938)
					(end 368.337846 -223.477074)
				)
				(arc
					(start 367.8682 -224.291144)
					(mid 367.848516 -224.338554)
					(end 367.841784 -224.389442)
				)
				(arc
					(start 367.841784 -224.389442)
					(mid 367.89944 -224.528636)
					(end 368.038634 -224.586292)
				)
				(arc
					(start 368.038634 -224.586292)
					(mid 368.137065 -224.559876)
					(end 368.209068 -224.48774)
				)
			)
		)
	)
	(zone
		(layers "F.Cu" "B.Cu" "In1.Cu" "In2.Cu" "In3.Cu" "In4.Cu" "In5.Cu" "In6.Cu"
			"In7.Cu" "In8.Cu" "In9.Cu" "In10.Cu" "In11.Cu" "In12.Cu" "In13.Cu" "In14.Cu"
			"In15.Cu" "In16.Cu"
		)
		(hatch none 0.5)
		(connect_pads
			(clearance 0)
		)
		(min_thickness 0.25)
		(keepout
			(tracks not_allowed)
			(vias allowed)
			(pads allowed)
			(copperpour not_allowed)
			(footprints allowed)
		)
		(placement
			(enabled no)
			(sheetname "")
		)
		(fill
			(thermal_gap 0.5)
			(thermal_bridge_width 0.5)
			(island_removal_mode 0)
		)
		(polygon
			(pts
				(arc
					(start 345.922346 -281.59202)
					(mid 345.264486 -281.59202)
					(end 345.922346 -281.59202)
				)
			)
		)
	)
	(zone
		(layers "F.Cu" "B.Cu" "In1.Cu" "In2.Cu" "In3.Cu" "In4.Cu" "In5.Cu" "In6.Cu"
			"In7.Cu" "In8.Cu" "In9.Cu" "In10.Cu" "In11.Cu" "In12.Cu" "In13.Cu" "In14.Cu"
			"In15.Cu" "In16.Cu"
		)
		(hatch none 0.5)
		(connect_pads
			(clearance 0)
		)
		(min_thickness 0.25)
		(keepout
			(tracks not_allowed)
			(vias allowed)
			(pads allowed)
			(copperpour not_allowed)
			(footprints allowed)
		)
		(placement
			(enabled no)
			(sheetname "")
		)
		(fill
			(thermal_gap 0.5)
			(thermal_bridge_width 0.5)
			(island_removal_mode 0)
		)
		(polygon
			(pts
				(arc
					(start 72.485758 -400.477228)
					(mid 72.104758 -400.858228)
					(end 72.485758 -401.239228)
				)
				(arc
					(start 73.349358 -401.239228)
					(mid 73.730358 -400.858228)
					(end 73.349358 -400.477228)
				)
			)
		)
	)
	(zone
		(layers "F.Cu" "B.Cu" "In1.Cu" "In2.Cu" "In3.Cu" "In4.Cu" "In5.Cu" "In6.Cu"
			"In7.Cu" "In8.Cu" "In9.Cu" "In10.Cu" "In11.Cu" "In12.Cu" "In13.Cu" "In14.Cu"
			"In15.Cu" "In16.Cu"
		)
		(hatch none 0.5)
		(connect_pads
			(clearance 0)
		)
		(min_thickness 0.25)
		(keepout
			(tracks not_allowed)
			(vias allowed)
			(pads allowed)
			(copperpour not_allowed)
			(footprints allowed)
		)
		(placement
			(enabled no)
			(sheetname "")
		)
		(fill
			(thermal_gap 0.5)
			(thermal_bridge_width 0.5)
			(island_removal_mode 0)
		)
		(polygon
			(pts
				(arc
					(start 380.694946 -288.103056)
					(mid 380.037086 -288.103056)
					(end 380.694946 -288.103056)
				)
			)
		)
	)
	(zone
		(layers "F.Cu" "B.Cu" "In1.Cu" "In2.Cu" "In3.Cu" "In4.Cu" "In5.Cu" "In6.Cu"
			"In7.Cu" "In8.Cu" "In9.Cu" "In10.Cu" "In11.Cu" "In12.Cu" "In13.Cu" "In14.Cu"
			"In15.Cu" "In16.Cu"
		)
		(hatch none 0.5)
		(connect_pads
			(clearance 0)
		)
		(min_thickness 0.25)
		(keepout
			(tracks not_allowed)
			(vias allowed)
			(pads allowed)
			(copperpour not_allowed)
			(footprints allowed)
		)
		(placement
			(enabled no)
			(sheetname "")
		)
		(fill
			(thermal_gap 0.5)
			(thermal_bridge_width 0.5)
			(island_removal_mode 0)
		)
		(polygon
			(pts
				(arc
					(start 107.57408 -213.646766)
					(mid 107.506372 -213.574915)
					(end 107.411266 -213.548468)
				)
				(arc
					(start 107.411266 -213.548468)
					(mid 107.281052 -213.602404)
					(end 107.227116 -213.732618)
				)
				(arc
					(start 107.227116 -213.732618)
					(mid 107.232567 -213.776839)
					(end 107.248452 -213.81847)
				)
				(arc
					(start 107.717844 -214.708486)
					(mid 107.785552 -214.780337)
					(end 107.880658 -214.806784)
				)
				(arc
					(start 107.880658 -214.806784)
					(mid 108.010872 -214.752848)
					(end 108.064808 -214.622634)
				)
				(arc
					(start 108.064808 -214.622634)
					(mid 108.059357 -214.578413)
					(end 108.043472 -214.536782)
				)
			)
		)
	)
	(zone
		(layers "F.Cu" "B.Cu" "In1.Cu" "In2.Cu" "In3.Cu" "In4.Cu" "In5.Cu" "In6.Cu"
			"In7.Cu" "In8.Cu" "In9.Cu" "In10.Cu" "In11.Cu" "In12.Cu" "In13.Cu" "In14.Cu"
			"In15.Cu" "In16.Cu"
		)
		(hatch none 0.5)
		(connect_pads
			(clearance 0)
		)
		(min_thickness 0.25)
		(keepout
			(tracks not_allowed)
			(vias allowed)
			(pads allowed)
			(copperpour not_allowed)
			(footprints allowed)
		)
		(placement
			(enabled no)
			(sheetname "")
		)
		(fill
			(thermal_gap 0.5)
			(thermal_bridge_width 0.5)
			(island_removal_mode 0)
		)
		(polygon
			(pts
				(arc
					(start 373.646192 -285.661354)
					(mid 372.988332 -285.661354)
					(end 373.646192 -285.661354)
				)
			)
		)
	)
	(zone
		(layers "F.Cu" "B.Cu" "In1.Cu" "In2.Cu" "In3.Cu" "In4.Cu" "In5.Cu" "In6.Cu"
			"In7.Cu" "In8.Cu" "In9.Cu" "In10.Cu" "In11.Cu" "In12.Cu" "In13.Cu" "In14.Cu"
			"In15.Cu" "In16.Cu"
		)
		(hatch none 0.5)
		(connect_pads
			(clearance 0)
		)
		(min_thickness 0.25)
		(keepout
			(tracks not_allowed)
			(vias allowed)
			(pads allowed)
			(copperpour not_allowed)
			(footprints allowed)
		)
		(placement
			(enabled no)
			(sheetname "")
		)
		(fill
			(thermal_gap 0.5)
			(thermal_bridge_width 0.5)
			(island_removal_mode 0)
		)
		(polygon
			(pts
				(arc
					(start 86.545928 -286.376872)
					(mid 86.473875 -286.304891)
					(end 86.375494 -286.278574)
				)
				(arc
					(start 86.375494 -286.278574)
					(mid 86.2363 -286.33623)
					(end 86.178644 -286.475424)
				)
				(arc
					(start 86.178644 -286.475424)
					(mid 86.185361 -286.52644)
					(end 86.20506 -286.573976)
				)
				(arc
					(start 86.67496 -287.387792)
					(mid 86.747013 -287.459773)
					(end 86.845394 -287.48609)
				)
				(arc
					(start 86.845394 -287.48609)
					(mid 86.984588 -287.428434)
					(end 87.042244 -287.28924)
				)
				(arc
					(start 87.042244 -287.28924)
					(mid 87.035527 -287.238224)
					(end 87.015828 -287.190688)
				)
			)
		)
	)
	(zone
		(layers "F.Cu" "B.Cu" "In1.Cu" "In2.Cu" "In3.Cu" "In4.Cu" "In5.Cu" "In6.Cu"
			"In7.Cu" "In8.Cu" "In9.Cu" "In10.Cu" "In11.Cu" "In12.Cu" "In13.Cu" "In14.Cu"
			"In15.Cu" "In16.Cu"
		)
		(hatch none 0.5)
		(connect_pads
			(clearance 0)
		)
		(min_thickness 0.25)
		(keepout
			(tracks not_allowed)
			(vias allowed)
			(pads allowed)
			(copperpour not_allowed)
			(footprints allowed)
		)
		(placement
			(enabled no)
			(sheetname "")
		)
		(fill
			(thermal_gap 0.5)
			(thermal_bridge_width 0.5)
			(island_removal_mode 0)
		)
		(polygon
			(pts
				(arc
					(start 102.023164 -276.708616)
					(mid 102.681024 -276.708616)
					(end 102.023164 -276.708616)
				)
			)
		)
	)
	(zone
		(layers "F.Cu" "B.Cu" "In1.Cu" "In2.Cu" "In3.Cu" "In4.Cu" "In5.Cu" "In6.Cu"
			"In7.Cu" "In8.Cu" "In9.Cu" "In10.Cu" "In11.Cu" "In12.Cu" "In13.Cu" "In14.Cu"
			"In15.Cu" "In16.Cu"
		)
		(hatch none 0.5)
		(connect_pads
			(clearance 0)
		)
		(min_thickness 0.25)
		(keepout
			(tracks not_allowed)
			(vias allowed)
			(pads allowed)
			(copperpour not_allowed)
			(footprints allowed)
		)
		(placement
			(enabled no)
			(sheetname "")
		)
		(fill
			(thermal_gap 0.5)
			(thermal_bridge_width 0.5)
			(island_removal_mode 0)
		)
		(polygon
			(pts
				(arc
					(start 114.629946 -214.720932)
					(mid 114.64963 -214.673522)
					(end 114.656362 -214.622634)
				)
				(arc
					(start 114.656362 -214.622634)
					(mid 114.598706 -214.48344)
					(end 114.459512 -214.425784)
				)
				(arc
					(start 114.459512 -214.425784)
					(mid 114.361081 -214.4522)
					(end 114.289078 -214.524336)
				)
				(arc
					(start 113.819178 -215.338406)
					(mid 113.799494 -215.385816)
					(end 113.792762 -215.436704)
				)
				(arc
					(start 113.792762 -215.436704)
					(mid 113.850418 -215.575898)
					(end 113.989612 -215.633554)
				)
				(arc
					(start 113.989612 -215.633554)
					(mid 114.088043 -215.607138)
					(end 114.160046 -215.535002)
				)
			)
		)
	)
	(zone
		(layers "F.Cu" "B.Cu" "In1.Cu" "In2.Cu" "In3.Cu" "In4.Cu" "In5.Cu" "In6.Cu"
			"In7.Cu" "In8.Cu" "In9.Cu" "In10.Cu" "In11.Cu" "In12.Cu" "In13.Cu" "In14.Cu"
			"In15.Cu" "In16.Cu"
		)
		(hatch none 0.5)
		(connect_pads
			(clearance 0)
		)
		(min_thickness 0.25)
		(keepout
			(tracks not_allowed)
			(vias allowed)
			(pads allowed)
			(copperpour not_allowed)
			(footprints allowed)
		)
		(placement
			(enabled no)
			(sheetname "")
		)
		(fill
			(thermal_gap 0.5)
			(thermal_bridge_width 0.5)
			(island_removal_mode 0)
		)
		(polygon
			(pts
				(arc
					(start 94.19336 -285.563056)
					(mid 94.173676 -285.610466)
					(end 94.166944 -285.661354)
				)
				(arc
					(start 94.166944 -285.661354)
					(mid 94.2246 -285.800548)
					(end 94.363794 -285.858204)
				)
				(arc
					(start 94.363794 -285.858204)
					(mid 94.462225 -285.831788)
					(end 94.534228 -285.759652)
				)
				(arc
					(start 95.004128 -284.945582)
					(mid 95.023812 -284.898172)
					(end 95.030544 -284.847284)
				)
				(arc
					(start 95.030544 -284.847284)
					(mid 94.972888 -284.70809)
					(end 94.833694 -284.650434)
				)
				(arc
					(start 94.833694 -284.650434)
					(mid 94.735263 -284.67685)
					(end 94.66326 -284.748986)
				)
			)
		)
	)
	(zone
		(layers "F.Cu" "B.Cu" "In1.Cu" "In2.Cu" "In3.Cu" "In4.Cu" "In5.Cu" "In6.Cu"
			"In7.Cu" "In8.Cu" "In9.Cu" "In10.Cu" "In11.Cu" "In12.Cu" "In13.Cu" "In14.Cu"
			"In15.Cu" "In16.Cu"
		)
		(hatch none 0.5)
		(connect_pads
			(clearance 0)
		)
		(min_thickness 0.25)
		(keepout
			(tracks not_allowed)
			(vias allowed)
			(pads allowed)
			(copperpour not_allowed)
			(footprints allowed)
		)
		(placement
			(enabled no)
			(sheetname "")
		)
		(fill
			(thermal_gap 0.5)
			(thermal_bridge_width 0.5)
			(island_removal_mode 0)
		)
		(polygon
			(pts
				(arc
					(start 91.1479 -206.024988)
					(mid 86.701884 -206.024988)
					(end 91.1479 -206.024988)
				)
			)
		)
	)
	(zone
		(layers "F.Cu" "B.Cu" "In1.Cu" "In2.Cu" "In3.Cu" "In4.Cu" "In5.Cu" "In6.Cu"
			"In7.Cu" "In8.Cu" "In9.Cu" "In10.Cu" "In11.Cu" "In12.Cu" "In13.Cu" "In14.Cu"
			"In15.Cu" "In16.Cu"
		)
		(hatch none 0.5)
		(connect_pads
			(clearance 0)
		)
		(min_thickness 0.25)
		(keepout
			(tracks not_allowed)
			(vias allowed)
			(pads allowed)
			(copperpour not_allowed)
			(footprints allowed)
		)
		(placement
			(enabled no)
			(sheetname "")
		)
		(fill
			(thermal_gap 0.5)
			(thermal_bridge_width 0.5)
			(island_removal_mode 0)
		)
		(polygon
			(pts
				(arc
					(start 340.738968 -403.502876)
					(mid 340.357968 -403.883876)
					(end 340.738968 -404.264876)
				)
				(arc
					(start 341.602568 -404.264876)
					(mid 341.983568 -403.883876)
					(end 341.602568 -403.502876)
				)
			)
		)
	)
	(zone
		(layers "F.Cu" "B.Cu" "In1.Cu" "In2.Cu" "In3.Cu" "In4.Cu" "In5.Cu" "In6.Cu"
			"In7.Cu" "In8.Cu" "In9.Cu" "In10.Cu" "In11.Cu" "In12.Cu" "In13.Cu" "In14.Cu"
			"In15.Cu" "In16.Cu"
		)
		(hatch none 0.5)
		(connect_pads
			(clearance 0)
		)
		(min_thickness 0.25)
		(keepout
			(tracks not_allowed)
			(vias allowed)
			(pads allowed)
			(copperpour not_allowed)
			(footprints allowed)
		)
		(placement
			(enabled no)
			(sheetname "")
		)
		(fill
			(thermal_gap 0.5)
			(thermal_bridge_width 0.5)
			(island_removal_mode 0)
		)
		(polygon
			(pts
				(arc
					(start 355.093524 -49.826672)
					(mid 354.712524 -50.207672)
					(end 355.093524 -50.588672)
				)
				(arc
					(start 355.957124 -50.588672)
					(mid 356.338124 -50.207672)
					(end 355.957124 -49.826672)
				)
			)
		)
	)
	(zone
		(layers "F.Cu" "B.Cu" "In1.Cu" "In2.Cu" "In3.Cu" "In4.Cu" "In5.Cu" "In6.Cu"
			"In7.Cu" "In8.Cu" "In9.Cu" "In10.Cu" "In11.Cu" "In12.Cu" "In13.Cu" "In14.Cu"
			"In15.Cu" "In16.Cu"
		)
		(hatch none 0.5)
		(connect_pads
			(clearance 0)
		)
		(min_thickness 0.25)
		(keepout
			(tracks not_allowed)
			(vias allowed)
			(pads allowed)
			(copperpour not_allowed)
			(footprints allowed)
		)
		(placement
			(enabled no)
			(sheetname "")
		)
		(fill
			(thermal_gap 0.5)
			(thermal_bridge_width 0.5)
			(island_removal_mode 0)
		)
		(polygon
			(pts
				(arc
					(start 91.1352 -221.035626)
					(mid 91.063211 -220.963467)
					(end 90.964766 -220.937074)
				)
				(arc
					(start 90.964766 -220.937074)
					(mid 90.825572 -220.99473)
					(end 90.767916 -221.133924)
				)
				(arc
					(start 90.767916 -221.133924)
					(mid 90.774673 -221.184805)
					(end 90.794332 -221.232222)
				)
				(arc
					(start 91.263978 -222.046038)
					(mid 91.335967 -222.118197)
					(end 91.434412 -222.14459)
				)
				(arc
					(start 91.434412 -222.14459)
					(mid 91.573606 -222.086934)
					(end 91.631262 -221.94774)
				)
				(arc
					(start 91.631262 -221.94774)
					(mid 91.624505 -221.896859)
					(end 91.604846 -221.849442)
				)
			)
		)
	)
	(zone
		(layers "F.Cu" "B.Cu" "In1.Cu" "In2.Cu" "In3.Cu" "In4.Cu" "In5.Cu" "In6.Cu"
			"In7.Cu" "In8.Cu" "In9.Cu" "In10.Cu" "In11.Cu" "In12.Cu" "In13.Cu" "In14.Cu"
			"In15.Cu" "In16.Cu"
		)
		(hatch none 0.5)
		(connect_pads
			(clearance 0)
		)
		(min_thickness 0.25)
		(keepout
			(tracks not_allowed)
			(vias allowed)
			(pads allowed)
			(copperpour not_allowed)
			(footprints allowed)
		)
		(placement
			(enabled no)
			(sheetname "")
		)
		(fill
			(thermal_gap 0.5)
			(thermal_bridge_width 0.5)
			(island_removal_mode 0)
		)
		(polygon
			(pts
				(arc
					(start 361.630468 -224.291144)
					(mid 361.558479 -224.218985)
					(end 361.460034 -224.192592)
				)
				(arc
					(start 361.460034 -224.192592)
					(mid 361.32084 -224.250248)
					(end 361.263184 -224.389442)
				)
				(arc
					(start 361.263184 -224.389442)
					(mid 361.269941 -224.440323)
					(end 361.2896 -224.48774)
				)
				(arc
					(start 361.759246 -225.301556)
					(mid 361.831235 -225.373715)
					(end 361.92968 -225.400108)
				)
				(arc
					(start 361.92968 -225.400108)
					(mid 362.068874 -225.342452)
					(end 362.12653 -225.203258)
				)
				(arc
					(start 362.12653 -225.203258)
					(mid 362.119773 -225.152377)
					(end 362.100114 -225.10496)
				)
			)
		)
	)
	(zone
		(layers "F.Cu" "B.Cu" "In1.Cu" "In2.Cu" "In3.Cu" "In4.Cu" "In5.Cu" "In6.Cu"
			"In7.Cu" "In8.Cu" "In9.Cu" "In10.Cu" "In11.Cu" "In12.Cu" "In13.Cu" "In14.Cu"
			"In15.Cu" "In16.Cu"
		)
		(hatch none 0.5)
		(connect_pads
			(clearance 0)
		)
		(min_thickness 0.25)
		(keepout
			(tracks not_allowed)
			(vias allowed)
			(pads allowed)
			(copperpour not_allowed)
			(footprints allowed)
		)
		(placement
			(enabled no)
			(sheetname "")
		)
		(fill
			(thermal_gap 0.5)
			(thermal_bridge_width 0.5)
			(island_removal_mode 0)
		)
		(polygon
			(pts
				(arc
					(start 376.2121 2.491994)
					(mid 376.5931 2.110994)
					(end 376.9741 2.491994)
				)
				(arc
					(start 376.9741 3.355594)
					(mid 376.5931 3.736594)
					(end 376.2121 3.355594)
				)
			)
		)
	)
	(zone
		(layers "F.Cu" "B.Cu" "In1.Cu" "In2.Cu" "In3.Cu" "In4.Cu" "In5.Cu" "In6.Cu"
			"In7.Cu" "In8.Cu" "In9.Cu" "In10.Cu" "In11.Cu" "In12.Cu" "In13.Cu" "In14.Cu"
			"In15.Cu" "In16.Cu"
		)
		(hatch none 0.5)
		(connect_pads
			(clearance 0)
		)
		(min_thickness 0.25)
		(keepout
			(tracks not_allowed)
			(vias allowed)
			(pads allowed)
			(copperpour not_allowed)
			(footprints allowed)
		)
		(placement
			(enabled no)
			(sheetname "")
		)
		(fill
			(thermal_gap 0.5)
			(thermal_bridge_width 0.5)
			(island_removal_mode 0)
		)
		(polygon
			(pts
				(arc
					(start 130.239262 -289.003232)
					(mid 130.255186 -288.961481)
					(end 130.260598 -288.917126)
				)
				(arc
					(start 130.260598 -288.917126)
					(mid 130.206662 -288.786912)
					(end 130.076448 -288.732976)
				)
				(arc
					(start 130.076448 -288.732976)
					(mid 129.981428 -288.759384)
					(end 129.913634 -288.83102)
				)
				(arc
					(start 129.44348 -289.721036)
					(mid 129.427556 -289.762787)
					(end 129.422144 -289.807142)
				)
				(arc
					(start 129.422144 -289.807142)
					(mid 129.47608 -289.937356)
					(end 129.606294 -289.991292)
				)
				(arc
					(start 129.606294 -289.991292)
					(mid 129.701314 -289.964884)
					(end 129.769108 -289.893248)
				)
			)
		)
	)
	(zone
		(layers "F.Cu" "B.Cu" "In1.Cu" "In2.Cu" "In3.Cu" "In4.Cu" "In5.Cu" "In6.Cu"
			"In7.Cu" "In8.Cu" "In9.Cu" "In10.Cu" "In11.Cu" "In12.Cu" "In13.Cu" "In14.Cu"
			"In15.Cu" "In16.Cu"
		)
		(hatch none 0.5)
		(connect_pads
			(clearance 0)
		)
		(min_thickness 0.25)
		(keepout
			(tracks not_allowed)
			(vias allowed)
			(pads allowed)
			(copperpour not_allowed)
			(footprints allowed)
		)
		(placement
			(enabled no)
			(sheetname "")
		)
		(fill
			(thermal_gap 0.5)
			(thermal_bridge_width 0.5)
			(island_removal_mode 0)
		)
		(polygon
			(pts
				(arc
					(start 353.874324 -180.392832)
					(mid 354.233534 -180.244042)
					(end 354.382324 -179.884832)
				)
				(arc
					(start 354.382324 -179.884832)
					(mid 354.314267 -179.630835)
					(end 354.128324 -179.444904)
				)
				(arc
					(start 353.204272 -178.91125)
					(mid 353.081978 -178.860713)
					(end 352.95078 -178.843432)
				)
				(arc
					(start 352.950272 -178.843432)
					(mid 352.591062 -178.992222)
					(end 352.442272 -179.351432)
				)
				(arc
					(start 352.442272 -179.351432)
					(mid 352.510329 -179.605429)
					(end 352.696272 -179.79136)
				)
				(arc
					(start 353.620324 -180.325014)
					(mid 353.742618 -180.375551)
					(end 353.873816 -180.392832)
				)
			)
		)
	)
	(zone
		(layers "F.Cu" "B.Cu" "In1.Cu" "In2.Cu" "In3.Cu" "In4.Cu" "In5.Cu" "In6.Cu"
			"In7.Cu" "In8.Cu" "In9.Cu" "In10.Cu" "In11.Cu" "In12.Cu" "In13.Cu" "In14.Cu"
			"In15.Cu" "In16.Cu"
		)
		(hatch none 0.5)
		(connect_pads
			(clearance 0)
		)
		(min_thickness 0.25)
		(keepout
			(tracks not_allowed)
			(vias allowed)
			(pads allowed)
			(copperpour not_allowed)
			(footprints allowed)
		)
		(placement
			(enabled no)
			(sheetname "")
		)
		(fill
			(thermal_gap 0.5)
			(thermal_bridge_width 0.5)
			(island_removal_mode 0)
		)
		(polygon
			(pts
				(arc
					(start 346.391992 -282.405836)
					(mid 345.734132 -282.405836)
					(end 346.391992 -282.405836)
				)
			)
		)
	)
	(zone
		(layers "F.Cu" "B.Cu" "In1.Cu" "In2.Cu" "In3.Cu" "In4.Cu" "In5.Cu" "In6.Cu"
			"In7.Cu" "In8.Cu" "In9.Cu" "In10.Cu" "In11.Cu" "In12.Cu" "In13.Cu" "In14.Cu"
			"In15.Cu" "In16.Cu"
		)
		(hatch none 0.5)
		(connect_pads
			(clearance 0)
		)
		(min_thickness 0.25)
		(keepout
			(tracks not_allowed)
			(vias allowed)
			(pads allowed)
			(copperpour not_allowed)
			(footprints allowed)
		)
		(placement
			(enabled no)
			(sheetname "")
		)
		(fill
			(thermal_gap 0.5)
			(thermal_bridge_width 0.5)
			(island_removal_mode 0)
		)
		(polygon
			(pts
				(arc
					(start 363.668564 -217.878406)
					(mid 363.010704 -217.878406)
					(end 363.668564 -217.878406)
				)
			)
		)
	)
	(zone
		(layers "F.Cu" "B.Cu" "In1.Cu" "In2.Cu" "In3.Cu" "In4.Cu" "In5.Cu" "In6.Cu"
			"In7.Cu" "In8.Cu" "In9.Cu" "In10.Cu" "In11.Cu" "In12.Cu" "In13.Cu" "In14.Cu"
			"In15.Cu" "In16.Cu"
		)
		(hatch none 0.5)
		(connect_pads
			(clearance 0)
		)
		(min_thickness 0.25)
		(keepout
			(tracks not_allowed)
			(vias allowed)
			(pads allowed)
			(copperpour not_allowed)
			(footprints allowed)
		)
		(placement
			(enabled no)
			(sheetname "")
		)
		(fill
			(thermal_gap 0.5)
			(thermal_bridge_width 0.5)
			(island_removal_mode 0)
		)
		(polygon
			(pts
				(arc
					(start 347.995748 -213.646766)
					(mid 347.92804 -213.574915)
					(end 347.832934 -213.548468)
				)
				(arc
					(start 347.832934 -213.548468)
					(mid 347.70272 -213.602404)
					(end 347.648784 -213.732618)
				)
				(arc
					(start 347.648784 -213.732618)
					(mid 347.654235 -213.776839)
					(end 347.67012 -213.81847)
				)
				(arc
					(start 348.139512 -214.708486)
					(mid 348.20722 -214.780337)
					(end 348.302326 -214.806784)
				)
				(arc
					(start 348.302326 -214.806784)
					(mid 348.43254 -214.752848)
					(end 348.486476 -214.622634)
				)
				(arc
					(start 348.486476 -214.622634)
					(mid 348.481025 -214.578413)
					(end 348.46514 -214.536782)
				)
			)
		)
	)
	(zone
		(layers "F.Cu" "B.Cu" "In1.Cu" "In2.Cu" "In3.Cu" "In4.Cu" "In5.Cu" "In6.Cu"
			"In7.Cu" "In8.Cu" "In9.Cu" "In10.Cu" "In11.Cu" "In12.Cu" "In13.Cu" "In14.Cu"
			"In15.Cu" "In16.Cu"
		)
		(hatch none 0.5)
		(connect_pads
			(clearance 0)
		)
		(min_thickness 0.25)
		(keepout
			(tracks not_allowed)
			(vias allowed)
			(pads allowed)
			(copperpour not_allowed)
			(footprints allowed)
		)
		(placement
			(enabled no)
			(sheetname "")
		)
		(fill
			(thermal_gap 0.5)
			(thermal_bridge_width 0.5)
			(island_removal_mode 0)
		)
		(polygon
			(pts
				(arc
					(start 377.29541 -218.692222)
					(mid 376.63755 -218.692222)
					(end 377.29541 -218.692222)
				)
			)
		)
	)
	(zone
		(layers "F.Cu" "B.Cu" "In1.Cu" "In2.Cu" "In3.Cu" "In4.Cu" "In5.Cu" "In6.Cu"
			"In7.Cu" "In8.Cu" "In9.Cu" "In10.Cu" "In11.Cu" "In12.Cu" "In13.Cu" "In14.Cu"
			"In15.Cu" "In16.Cu"
		)
		(hatch none 0.5)
		(connect_pads
			(clearance 0)
		)
		(min_thickness 0.25)
		(keepout
			(tracks not_allowed)
			(vias allowed)
			(pads allowed)
			(copperpour not_allowed)
			(footprints allowed)
		)
		(placement
			(enabled no)
			(sheetname "")
		)
		(fill
			(thermal_gap 0.5)
			(thermal_bridge_width 0.5)
			(island_removal_mode 0)
		)
		(polygon
			(pts
				(arc
					(start 72.142096 -425.360592)
					(mid 72.164414 -425.414474)
					(end 72.218296 -425.436792)
				)
				(arc
					(start 73.158096 -425.436792)
					(mid 73.211978 -425.414474)
					(end 73.234296 -425.360592)
				)
				(arc
					(start 73.234296 -422.819068)
					(mid 73.211978 -422.765186)
					(end 73.158096 -422.742868)
				)
				(arc
					(start 72.218296 -422.742868)
					(mid 72.164414 -422.765186)
					(end 72.142096 -422.819068)
				)
			)
		)
	)
	(zone
		(layers "F.Cu" "B.Cu" "In1.Cu" "In2.Cu" "In3.Cu" "In4.Cu" "In5.Cu" "In6.Cu"
			"In7.Cu" "In8.Cu" "In9.Cu" "In10.Cu" "In11.Cu" "In12.Cu" "In13.Cu" "In14.Cu"
			"In15.Cu" "In16.Cu"
		)
		(hatch none 0.5)
		(connect_pads
			(clearance 0)
		)
		(min_thickness 0.25)
		(keepout
			(tracks not_allowed)
			(vias allowed)
			(pads allowed)
			(copperpour not_allowed)
			(footprints allowed)
		)
		(placement
			(enabled no)
			(sheetname "")
		)
		(fill
			(thermal_gap 0.5)
			(thermal_bridge_width 0.5)
			(island_removal_mode 0)
		)
		(polygon
			(pts
				(arc
					(start 101.942646 -220.418152)
					(mid 101.96233 -220.370742)
					(end 101.969062 -220.319854)
				)
				(arc
					(start 101.969062 -220.319854)
					(mid 101.911406 -220.18066)
					(end 101.772212 -220.123004)
				)
				(arc
					(start 101.772212 -220.123004)
					(mid 101.673781 -220.14942)
					(end 101.601778 -220.221556)
				)
				(arc
					(start 101.132132 -221.035626)
					(mid 101.112448 -221.083036)
					(end 101.105716 -221.133924)
				)
				(arc
					(start 101.105716 -221.133924)
					(mid 101.163372 -221.273118)
					(end 101.302566 -221.330774)
				)
				(arc
					(start 101.302566 -221.330774)
					(mid 101.400997 -221.304358)
					(end 101.473 -221.232222)
				)
			)
		)
	)
	(zone
		(layers "F.Cu" "B.Cu" "In1.Cu" "In2.Cu" "In3.Cu" "In4.Cu" "In5.Cu" "In6.Cu"
			"In7.Cu" "In8.Cu" "In9.Cu" "In10.Cu" "In11.Cu" "In12.Cu" "In13.Cu" "In14.Cu"
			"In15.Cu" "In16.Cu"
		)
		(hatch none 0.5)
		(connect_pads
			(clearance 0)
		)
		(min_thickness 0.25)
		(keepout
			(tracks not_allowed)
			(vias allowed)
			(pads allowed)
			(copperpour not_allowed)
			(footprints allowed)
		)
		(placement
			(enabled no)
			(sheetname "")
		)
		(fill
			(thermal_gap 0.5)
			(thermal_bridge_width 0.5)
			(island_removal_mode 0)
		)
		(polygon
			(pts
				(arc
					(start 153.850594 -403.502876)
					(mid 153.469594 -403.883876)
					(end 153.850594 -404.264876)
				)
				(arc
					(start 154.714194 -404.264876)
					(mid 155.095194 -403.883876)
					(end 154.714194 -403.502876)
				)
			)
		)
	)
	(zone
		(layers "F.Cu" "B.Cu" "In1.Cu" "In2.Cu" "In3.Cu" "In4.Cu" "In5.Cu" "In6.Cu"
			"In7.Cu" "In8.Cu" "In9.Cu" "In10.Cu" "In11.Cu" "In12.Cu" "In13.Cu" "In14.Cu"
			"In15.Cu" "In16.Cu"
		)
		(hatch none 0.5)
		(connect_pads
			(clearance 0)
		)
		(min_thickness 0.25)
		(keepout
			(tracks not_allowed)
			(vias allowed)
			(pads allowed)
			(copperpour not_allowed)
			(footprints allowed)
		)
		(placement
			(enabled no)
			(sheetname "")
		)
		(fill
			(thermal_gap 0.5)
			(thermal_bridge_width 0.5)
			(island_removal_mode 0)
		)
		(polygon
			(pts
				(arc
					(start 374.48617 -400.477228)
					(mid 374.10517 -400.858228)
					(end 374.48617 -401.239228)
				)
				(arc
					(start 375.34977 -401.239228)
					(mid 375.73077 -400.858228)
					(end 375.34977 -400.477228)
				)
			)
		)
	)
	(zone
		(layers "F.Cu" "B.Cu" "In1.Cu" "In2.Cu" "In3.Cu" "In4.Cu" "In5.Cu" "In6.Cu"
			"In7.Cu" "In8.Cu" "In9.Cu" "In10.Cu" "In11.Cu" "In12.Cu" "In13.Cu" "In14.Cu"
			"In15.Cu" "In16.Cu"
		)
		(hatch none 0.5)
		(connect_pads
			(clearance 0)
		)
		(min_thickness 0.25)
		(keepout
			(tracks not_allowed)
			(vias allowed)
			(pads allowed)
			(copperpour not_allowed)
			(footprints allowed)
		)
		(placement
			(enabled no)
			(sheetname "")
		)
		(fill
			(thermal_gap 0.5)
			(thermal_bridge_width 0.5)
			(island_removal_mode 0)
		)
		(polygon
			(pts
				(arc
					(start 370.826792 -285.661354)
					(mid 370.168932 -285.661354)
					(end 370.826792 -285.661354)
				)
			)
		)
	)
	(zone
		(layers "F.Cu" "B.Cu" "In1.Cu" "In2.Cu" "In3.Cu" "In4.Cu" "In5.Cu" "In6.Cu"
			"In7.Cu" "In8.Cu" "In9.Cu" "In10.Cu" "In11.Cu" "In12.Cu" "In13.Cu" "In14.Cu"
			"In15.Cu" "In16.Cu"
		)
		(hatch none 0.5)
		(connect_pads
			(clearance 0)
		)
		(min_thickness 0.25)
		(keepout
			(tracks not_allowed)
			(vias allowed)
			(pads allowed)
			(copperpour not_allowed)
			(footprints allowed)
		)
		(placement
			(enabled no)
			(sheetname "")
		)
		(fill
			(thermal_gap 0.5)
			(thermal_bridge_width 0.5)
			(island_removal_mode 0)
		)
		(polygon
			(pts
				(arc
					(start 132.014468 -17.763744)
					(mid 131.633468 -18.144744)
					(end 132.014468 -18.525744)
				)
				(arc
					(start 132.878068 -18.525744)
					(mid 133.259068 -18.144744)
					(end 132.878068 -17.763744)
				)
			)
		)
	)
	(zone
		(layers "F.Cu" "B.Cu" "In1.Cu" "In2.Cu" "In3.Cu" "In4.Cu" "In5.Cu" "In6.Cu"
			"In7.Cu" "In8.Cu" "In9.Cu" "In10.Cu" "In11.Cu" "In12.Cu" "In13.Cu" "In14.Cu"
			"In15.Cu" "In16.Cu"
		)
		(hatch none 0.5)
		(connect_pads
			(clearance 0)
		)
		(min_thickness 0.25)
		(keepout
			(tracks not_allowed)
			(vias allowed)
			(pads allowed)
			(copperpour not_allowed)
			(footprints allowed)
		)
		(placement
			(enabled no)
			(sheetname "")
		)
		(fill
			(thermal_gap 0.5)
			(thermal_bridge_width 0.5)
			(island_removal_mode 0)
		)
		(polygon
			(pts
				(arc
					(start 327.352914 7.571994)
					(mid 327.733914 7.190994)
					(end 328.114914 7.571994)
				)
				(arc
					(start 328.114914 8.435594)
					(mid 327.733914 8.816594)
					(end 327.352914 8.435594)
				)
			)
		)
	)
	(zone
		(layers "F.Cu" "B.Cu" "In1.Cu" "In2.Cu" "In3.Cu" "In4.Cu" "In5.Cu" "In6.Cu"
			"In7.Cu" "In8.Cu" "In9.Cu" "In10.Cu" "In11.Cu" "In12.Cu" "In13.Cu" "In14.Cu"
			"In15.Cu" "In16.Cu"
		)
		(hatch none 0.5)
		(connect_pads
			(clearance 0)
		)
		(min_thickness 0.25)
		(keepout
			(tracks not_allowed)
			(vias allowed)
			(pads allowed)
			(copperpour not_allowed)
			(footprints allowed)
		)
		(placement
			(enabled no)
			(sheetname "")
		)
		(fill
			(thermal_gap 0.5)
			(thermal_bridge_width 0.5)
			(island_removal_mode 0)
		)
		(polygon
			(pts
				(arc
					(start 371.766846 -288.917126)
					(mid 371.108986 -288.917126)
					(end 371.766846 -288.917126)
				)
			)
		)
	)
	(zone
		(layers "F.Cu" "B.Cu" "In1.Cu" "In2.Cu" "In3.Cu" "In4.Cu" "In5.Cu" "In6.Cu"
			"In7.Cu" "In8.Cu" "In9.Cu" "In10.Cu" "In11.Cu" "In12.Cu" "In13.Cu" "In14.Cu"
			"In15.Cu" "In16.Cu"
		)
		(hatch none 0.5)
		(connect_pads
			(clearance 0)
		)
		(min_thickness 0.25)
		(keepout
			(tracks not_allowed)
			(vias allowed)
			(pads allowed)
			(copperpour not_allowed)
			(footprints allowed)
		)
		(placement
			(enabled no)
			(sheetname "")
		)
		(fill
			(thermal_gap 0.5)
			(thermal_bridge_width 0.5)
			(island_removal_mode 0)
		)
		(polygon
			(pts
				(arc
					(start 376.465846 -288.917126)
					(mid 375.807986 -288.917126)
					(end 376.465846 -288.917126)
				)
			)
		)
	)
	(zone
		(layers "F.Cu" "B.Cu" "In1.Cu" "In2.Cu" "In3.Cu" "In4.Cu" "In5.Cu" "In6.Cu"
			"In7.Cu" "In8.Cu" "In9.Cu" "In10.Cu" "In11.Cu" "In12.Cu" "In13.Cu" "In14.Cu"
			"In15.Cu" "In16.Cu"
		)
		(hatch none 0.5)
		(connect_pads
			(clearance 0)
		)
		(min_thickness 0.25)
		(keepout
			(tracks not_allowed)
			(vias allowed)
			(pads allowed)
			(copperpour not_allowed)
			(footprints allowed)
		)
		(placement
			(enabled no)
			(sheetname "")
		)
		(fill
			(thermal_gap 0.5)
			(thermal_bridge_width 0.5)
			(island_removal_mode 0)
		)
		(polygon
			(pts
				(arc
					(start 370.356892 -289.807142)
					(mid 369.699032 -289.807142)
					(end 370.356892 -289.807142)
				)
			)
		)
	)
	(zone
		(layers "F.Cu" "B.Cu" "In1.Cu" "In2.Cu" "In3.Cu" "In4.Cu" "In5.Cu" "In6.Cu"
			"In7.Cu" "In8.Cu" "In9.Cu" "In10.Cu" "In11.Cu" "In12.Cu" "In13.Cu" "In14.Cu"
			"In15.Cu" "In16.Cu"
		)
		(hatch none 0.5)
		(connect_pads
			(clearance 0)
		)
		(min_thickness 0.25)
		(keepout
			(tracks not_allowed)
			(vias allowed)
			(pads allowed)
			(copperpour not_allowed)
			(footprints allowed)
		)
		(placement
			(enabled no)
			(sheetname "")
		)
		(fill
			(thermal_gap 0.5)
			(thermal_bridge_width 0.5)
			(island_removal_mode 0)
		)
		(polygon
			(pts
				(arc
					(start 96.07296 -285.563056)
					(mid 96.053276 -285.610466)
					(end 96.046544 -285.661354)
				)
				(arc
					(start 96.046544 -285.661354)
					(mid 96.1042 -285.800548)
					(end 96.243394 -285.858204)
				)
				(arc
					(start 96.243394 -285.858204)
					(mid 96.341825 -285.831788)
					(end 96.413828 -285.759652)
				)
				(arc
					(start 96.883728 -284.945582)
					(mid 96.903412 -284.898172)
					(end 96.910144 -284.847284)
				)
				(arc
					(start 96.910144 -284.847284)
					(mid 96.852488 -284.70809)
					(end 96.713294 -284.650434)
				)
				(arc
					(start 96.713294 -284.650434)
					(mid 96.614863 -284.67685)
					(end 96.54286 -284.748986)
				)
			)
		)
	)
	(zone
		(layers "F.Cu" "B.Cu" "In1.Cu" "In2.Cu" "In3.Cu" "In4.Cu" "In5.Cu" "In6.Cu"
			"In7.Cu" "In8.Cu" "In9.Cu" "In10.Cu" "In11.Cu" "In12.Cu" "In13.Cu" "In14.Cu"
			"In15.Cu" "In16.Cu"
		)
		(hatch none 0.5)
		(connect_pads
			(clearance 0)
		)
		(min_thickness 0.25)
		(keepout
			(tracks not_allowed)
			(vias allowed)
			(pads allowed)
			(copperpour not_allowed)
			(footprints allowed)
		)
		(placement
			(enabled no)
			(sheetname "")
		)
		(fill
			(thermal_gap 0.5)
			(thermal_bridge_width 0.5)
			(island_removal_mode 0)
		)
		(polygon
			(pts
				(arc
					(start 351.87255 -280.679652)
					(mid 351.800561 -280.607493)
					(end 351.702116 -280.5811)
				)
				(arc
					(start 351.702116 -280.5811)
					(mid 351.562922 -280.638756)
					(end 351.505266 -280.77795)
				)
				(arc
					(start 351.505266 -280.77795)
					(mid 351.512023 -280.828831)
					(end 351.531682 -280.876248)
				)
				(arc
					(start 352.001582 -281.690318)
					(mid 352.073571 -281.762477)
					(end 352.172016 -281.78887)
				)
				(arc
					(start 352.172016 -281.78887)
					(mid 352.31121 -281.731214)
					(end 352.368866 -281.59202)
				)
				(arc
					(start 352.368866 -281.59202)
					(mid 352.362109 -281.541139)
					(end 352.34245 -281.493722)
				)
			)
		)
	)
	(zone
		(layers "F.Cu" "B.Cu" "In1.Cu" "In2.Cu" "In3.Cu" "In4.Cu" "In5.Cu" "In6.Cu"
			"In7.Cu" "In8.Cu" "In9.Cu" "In10.Cu" "In11.Cu" "In12.Cu" "In13.Cu" "In14.Cu"
			"In15.Cu" "In16.Cu"
		)
		(hatch none 0.5)
		(connect_pads
			(clearance 0)
		)
		(min_thickness 0.25)
		(keepout
			(tracks not_allowed)
			(vias allowed)
			(pads allowed)
			(copperpour not_allowed)
			(footprints allowed)
		)
		(placement
			(enabled no)
			(sheetname "")
		)
		(fill
			(thermal_gap 0.5)
			(thermal_bridge_width 0.5)
			(island_removal_mode 0)
		)
		(polygon
			(pts
				(arc
					(start 345.65336 -214.720932)
					(mid 345.673044 -214.673522)
					(end 345.679776 -214.622634)
				)
				(arc
					(start 345.679776 -214.622634)
					(mid 345.62212 -214.48344)
					(end 345.482926 -214.425784)
				)
				(arc
					(start 345.482926 -214.425784)
					(mid 345.384495 -214.4522)
					(end 345.312492 -214.524336)
				)
				(arc
					(start 344.842846 -215.338406)
					(mid 344.823162 -215.385816)
					(end 344.81643 -215.436704)
				)
				(arc
					(start 344.81643 -215.436704)
					(mid 344.874086 -215.575898)
					(end 345.01328 -215.633554)
				)
				(arc
					(start 345.01328 -215.633554)
					(mid 345.111711 -215.607138)
					(end 345.183714 -215.535002)
				)
			)
		)
	)
	(zone
		(layers "F.Cu" "B.Cu" "In1.Cu" "In2.Cu" "In3.Cu" "In4.Cu" "In5.Cu" "In6.Cu"
			"In7.Cu" "In8.Cu" "In9.Cu" "In10.Cu" "In11.Cu" "In12.Cu" "In13.Cu" "In14.Cu"
			"In15.Cu" "In16.Cu"
		)
		(hatch none 0.5)
		(connect_pads
			(clearance 0)
		)
		(min_thickness 0.25)
		(keepout
			(tracks not_allowed)
			(vias allowed)
			(pads allowed)
			(copperpour not_allowed)
			(footprints allowed)
		)
		(placement
			(enabled no)
			(sheetname "")
		)
		(fill
			(thermal_gap 0.5)
			(thermal_bridge_width 0.5)
			(island_removal_mode 0)
		)
		(polygon
			(pts
				(arc
					(start 101.113082 -280.679652)
					(mid 101.041093 -280.607493)
					(end 100.942648 -280.5811)
				)
				(arc
					(start 100.942648 -280.5811)
					(mid 100.803454 -280.638756)
					(end 100.745798 -280.77795)
				)
				(arc
					(start 100.745798 -280.77795)
					(mid 100.752555 -280.828831)
					(end 100.772214 -280.876248)
				)
				(arc
					(start 101.242114 -281.690318)
					(mid 101.314103 -281.762477)
					(end 101.412548 -281.78887)
				)
				(arc
					(start 101.412548 -281.78887)
					(mid 101.551742 -281.731214)
					(end 101.609398 -281.59202)
				)
				(arc
					(start 101.609398 -281.59202)
					(mid 101.602641 -281.541139)
					(end 101.582982 -281.493722)
				)
			)
		)
	)
	(zone
		(layers "F.Cu" "B.Cu" "In1.Cu" "In2.Cu" "In3.Cu" "In4.Cu" "In5.Cu" "In6.Cu"
			"In7.Cu" "In8.Cu" "In9.Cu" "In10.Cu" "In11.Cu" "In12.Cu" "In13.Cu" "In14.Cu"
			"In15.Cu" "In16.Cu"
		)
		(hatch none 0.5)
		(connect_pads
			(clearance 0)
		)
		(min_thickness 0.25)
		(keepout
			(tracks not_allowed)
			(vias allowed)
			(pads allowed)
			(copperpour not_allowed)
			(footprints allowed)
		)
		(placement
			(enabled no)
			(sheetname "")
		)
		(fill
			(thermal_gap 0.5)
			(thermal_bridge_width 0.5)
			(island_removal_mode 0)
		)
		(polygon
			(pts
				(arc
					(start 52.389278 -409.649168)
					(mid 52.008278 -410.030168)
					(end 52.389278 -410.411168)
				)
				(arc
					(start 53.252878 -410.411168)
					(mid 53.633878 -410.030168)
					(end 53.252878 -409.649168)
				)
			)
		)
	)
	(zone
		(layers "F.Cu" "B.Cu" "In1.Cu" "In2.Cu" "In3.Cu" "In4.Cu" "In5.Cu" "In6.Cu"
			"In7.Cu" "In8.Cu" "In9.Cu" "In10.Cu" "In11.Cu" "In12.Cu" "In13.Cu" "In14.Cu"
			"In15.Cu" "In16.Cu"
		)
		(hatch none 0.5)
		(connect_pads
			(clearance 0)
		)
		(min_thickness 0.25)
		(keepout
			(tracks not_allowed)
			(vias allowed)
			(pads allowed)
			(copperpour not_allowed)
			(footprints allowed)
		)
		(placement
			(enabled no)
			(sheetname "")
		)
		(fill
			(thermal_gap 0.5)
			(thermal_bridge_width 0.5)
			(island_removal_mode 0)
		)
		(polygon
			(pts
				(arc
					(start 357.55961 -220.319854)
					(mid 356.90175 -220.319854)
					(end 357.55961 -220.319854)
				)
			)
		)
	)
	(zone
		(layers "F.Cu" "B.Cu" "In1.Cu" "In2.Cu" "In3.Cu" "In4.Cu" "In5.Cu" "In6.Cu"
			"In7.Cu" "In8.Cu" "In9.Cu" "In10.Cu" "In11.Cu" "In12.Cu" "In13.Cu" "In14.Cu"
			"In15.Cu" "In16.Cu"
		)
		(hatch none 0.5)
		(connect_pads
			(clearance 0)
		)
		(min_thickness 0.25)
		(keepout
			(tracks not_allowed)
			(vias allowed)
			(pads allowed)
			(copperpour not_allowed)
			(footprints allowed)
		)
		(placement
			(enabled no)
			(sheetname "")
		)
		(fill
			(thermal_gap 0.5)
			(thermal_bridge_width 0.5)
			(island_removal_mode 0)
		)
		(polygon
			(pts
				(arc
					(start 380.694946 -284.847538)
					(mid 380.037086 -284.847538)
					(end 380.694946 -284.847538)
				)
			)
		)
	)
	(zone
		(layers "F.Cu" "B.Cu" "In1.Cu" "In2.Cu" "In3.Cu" "In4.Cu" "In5.Cu" "In6.Cu"
			"In7.Cu" "In8.Cu" "In9.Cu" "In10.Cu" "In11.Cu" "In12.Cu" "In13.Cu" "In14.Cu"
			"In15.Cu" "In16.Cu"
		)
		(hatch none 0.5)
		(connect_pads
			(clearance 0)
		)
		(min_thickness 0.25)
		(keepout
			(tracks not_allowed)
			(vias allowed)
			(pads allowed)
			(copperpour not_allowed)
			(footprints allowed)
		)
		(placement
			(enabled no)
			(sheetname "")
		)
		(fill
			(thermal_gap 0.5)
			(thermal_bridge_width 0.5)
			(island_removal_mode 0)
		)
		(polygon
			(pts
				(arc
					(start 348.657672 -182.805832)
					(mid 348.806462 -183.165042)
					(end 349.165672 -183.313832)
				)
				(arc
					(start 349.16618 -183.313832)
					(mid 349.297389 -183.296595)
					(end 349.419672 -183.246014)
				)
				(arc
					(start 350.343724 -182.71236)
					(mid 350.529657 -182.526424)
					(end 350.597724 -182.272432)
				)
				(arc
					(start 350.597724 -182.272432)
					(mid 350.448934 -181.913222)
					(end 350.089724 -181.764432)
				)
				(arc
					(start 350.089216 -181.764432)
					(mid 349.958007 -181.781669)
					(end 349.835724 -181.83225)
				)
				(arc
					(start 348.911672 -182.365904)
					(mid 348.725739 -182.55184)
					(end 348.657672 -182.805832)
				)
			)
		)
	)
	(zone
		(layers "F.Cu" "B.Cu" "In1.Cu" "In2.Cu" "In3.Cu" "In4.Cu" "In5.Cu" "In6.Cu"
			"In7.Cu" "In8.Cu" "In9.Cu" "In10.Cu" "In11.Cu" "In12.Cu" "In13.Cu" "In14.Cu"
			"In15.Cu" "In16.Cu"
		)
		(hatch none 0.5)
		(connect_pads
			(clearance 0)
		)
		(min_thickness 0.25)
		(keepout
			(tracks not_allowed)
			(vias allowed)
			(pads allowed)
			(copperpour not_allowed)
			(footprints allowed)
		)
		(placement
			(enabled no)
			(sheetname "")
		)
		(fill
			(thermal_gap 0.5)
			(thermal_bridge_width 0.5)
			(island_removal_mode 0)
		)
		(polygon
			(pts
				(arc
					(start 129.344674 -400.477228)
					(mid 128.963674 -400.858228)
					(end 129.344674 -401.239228)
				)
				(arc
					(start 130.208274 -401.239228)
					(mid 130.589274 -400.858228)
					(end 130.208274 -400.477228)
				)
			)
		)
	)
	(zone
		(layers "F.Cu" "B.Cu" "In1.Cu" "In2.Cu" "In3.Cu" "In4.Cu" "In5.Cu" "In6.Cu"
			"In7.Cu" "In8.Cu" "In9.Cu" "In10.Cu" "In11.Cu" "In12.Cu" "In13.Cu" "In14.Cu"
			"In15.Cu" "In16.Cu"
		)
		(hatch none 0.5)
		(connect_pads
			(clearance 0)
		)
		(min_thickness 0.25)
		(keepout
			(tracks not_allowed)
			(vias allowed)
			(pads allowed)
			(copperpour not_allowed)
			(footprints allowed)
		)
		(placement
			(enabled no)
			(sheetname "")
		)
		(fill
			(thermal_gap 0.5)
			(thermal_bridge_width 0.5)
			(island_removal_mode 0)
		)
		(polygon
			(pts
				(arc
					(start 360.37901 -218.692222)
					(mid 359.72115 -218.692222)
					(end 360.37901 -218.692222)
				)
			)
		)
	)
	(zone
		(layers "F.Cu" "B.Cu" "In1.Cu" "In2.Cu" "In3.Cu" "In4.Cu" "In5.Cu" "In6.Cu"
			"In7.Cu" "In8.Cu" "In9.Cu" "In10.Cu" "In11.Cu" "In12.Cu" "In13.Cu" "In14.Cu"
			"In15.Cu" "In16.Cu"
		)
		(hatch none 0.5)
		(connect_pads
			(clearance 0)
		)
		(min_thickness 0.25)
		(keepout
			(tracks not_allowed)
			(vias allowed)
			(pads allowed)
			(copperpour not_allowed)
			(footprints allowed)
		)
		(placement
			(enabled no)
			(sheetname "")
		)
		(fill
			(thermal_gap 0.5)
			(thermal_bridge_width 0.5)
			(island_removal_mode 0)
		)
		(polygon
			(pts
				(arc
					(start 107.581954 -220.22181)
					(mid 107.509965 -220.149651)
					(end 107.41152 -220.123258)
				)
				(arc
					(start 107.41152 -220.123258)
					(mid 107.272326 -220.180914)
					(end 107.21467 -220.320108)
				)
				(arc
					(start 107.21467 -220.320108)
					(mid 107.221427 -220.370989)
					(end 107.241086 -220.418406)
				)
				(arc
					(start 107.710732 -221.232222)
					(mid 107.782721 -221.304381)
					(end 107.881166 -221.330774)
				)
				(arc
					(start 107.881166 -221.330774)
					(mid 108.02036 -221.273118)
					(end 108.078016 -221.133924)
				)
				(arc
					(start 108.078016 -221.133924)
					(mid 108.071259 -221.083043)
					(end 108.0516 -221.035626)
				)
			)
		)
	)
	(zone
		(layers "F.Cu" "B.Cu" "In1.Cu" "In2.Cu" "In3.Cu" "In4.Cu" "In5.Cu" "In6.Cu"
			"In7.Cu" "In8.Cu" "In9.Cu" "In10.Cu" "In11.Cu" "In12.Cu" "In13.Cu" "In14.Cu"
			"In15.Cu" "In16.Cu"
		)
		(hatch none 0.5)
		(connect_pads
			(clearance 0)
		)
		(min_thickness 0.25)
		(keepout
			(tracks not_allowed)
			(vias allowed)
			(pads allowed)
			(copperpour not_allowed)
			(footprints allowed)
		)
		(placement
			(enabled no)
			(sheetname "")
		)
		(fill
			(thermal_gap 0.5)
			(thermal_bridge_width 0.5)
			(island_removal_mode 0)
		)
		(polygon
			(pts
				(arc
					(start 24.421338 -4.581652)
					(mid 24.040338 -4.962652)
					(end 24.421338 -5.343652)
				)
				(arc
					(start 25.284938 -5.343652)
					(mid 25.665938 -4.962652)
					(end 25.284938 -4.581652)
				)
			)
		)
	)
	(zone
		(layers "F.Cu" "B.Cu" "In1.Cu" "In2.Cu" "In3.Cu" "In4.Cu" "In5.Cu" "In6.Cu"
			"In7.Cu" "In8.Cu" "In9.Cu" "In10.Cu" "In11.Cu" "In12.Cu" "In13.Cu" "In14.Cu"
			"In15.Cu" "In16.Cu"
		)
		(hatch none 0.5)
		(connect_pads
			(clearance 0)
		)
		(min_thickness 0.25)
		(keepout
			(tracks not_allowed)
			(vias allowed)
			(pads allowed)
			(copperpour not_allowed)
			(footprints allowed)
		)
		(placement
			(enabled no)
			(sheetname "")
		)
		(fill
			(thermal_gap 0.5)
			(thermal_bridge_width 0.5)
			(island_removal_mode 0)
		)
		(polygon
			(pts
				(arc
					(start 376.2121 7.571994)
					(mid 376.5931 7.190994)
					(end 376.9741 7.571994)
				)
				(arc
					(start 376.9741 8.435594)
					(mid 376.5931 8.816594)
					(end 376.2121 8.435594)
				)
			)
		)
	)
	(zone
		(layers "F.Cu" "B.Cu" "In1.Cu" "In2.Cu" "In3.Cu" "In4.Cu" "In5.Cu" "In6.Cu"
			"In7.Cu" "In8.Cu" "In9.Cu" "In10.Cu" "In11.Cu" "In12.Cu" "In13.Cu" "In14.Cu"
			"In15.Cu" "In16.Cu"
		)
		(hatch none 0.5)
		(connect_pads
			(clearance 0)
		)
		(min_thickness 0.25)
		(keepout
			(tracks not_allowed)
			(vias allowed)
			(pads allowed)
			(copperpour not_allowed)
			(footprints allowed)
		)
		(placement
			(enabled no)
			(sheetname "")
		)
		(fill
			(thermal_gap 0.5)
			(thermal_bridge_width 0.5)
			(island_removal_mode 0)
		)
		(polygon
			(pts
				(arc
					(start 360.849164 -217.878406)
					(mid 360.191304 -217.878406)
					(end 360.849164 -217.878406)
				)
			)
		)
	)
	(zone
		(layers "F.Cu" "B.Cu" "In1.Cu" "In2.Cu" "In3.Cu" "In4.Cu" "In5.Cu" "In6.Cu"
			"In7.Cu" "In8.Cu" "In9.Cu" "In10.Cu" "In11.Cu" "In12.Cu" "In13.Cu" "In14.Cu"
			"In15.Cu" "In16.Cu"
		)
		(hatch none 0.5)
		(connect_pads
			(clearance 0)
		)
		(min_thickness 0.25)
		(keepout
			(tracks not_allowed)
			(vias allowed)
			(pads allowed)
			(copperpour not_allowed)
			(footprints allowed)
		)
		(placement
			(enabled no)
			(sheetname "")
		)
		(fill
			(thermal_gap 0.5)
			(thermal_bridge_width 0.5)
			(island_removal_mode 0)
		)
		(polygon
			(pts
				(arc
					(start 116.509292 -214.720932)
					(mid 116.528976 -214.673522)
					(end 116.535708 -214.622634)
				)
				(arc
					(start 116.535708 -214.622634)
					(mid 116.478052 -214.48344)
					(end 116.338858 -214.425784)
				)
				(arc
					(start 116.338858 -214.425784)
					(mid 116.240427 -214.4522)
					(end 116.168424 -214.524336)
				)
				(arc
					(start 115.698778 -215.338406)
					(mid 115.679094 -215.385816)
					(end 115.672362 -215.436704)
				)
				(arc
					(start 115.672362 -215.436704)
					(mid 115.730018 -215.575898)
					(end 115.869212 -215.633554)
				)
				(arc
					(start 115.869212 -215.633554)
					(mid 115.967643 -215.607138)
					(end 116.039646 -215.535002)
				)
			)
		)
	)
	(zone
		(layers "F.Cu" "B.Cu" "In1.Cu" "In2.Cu" "In3.Cu" "In4.Cu" "In5.Cu" "In6.Cu"
			"In7.Cu" "In8.Cu" "In9.Cu" "In10.Cu" "In11.Cu" "In12.Cu" "In13.Cu" "In14.Cu"
			"In15.Cu" "In16.Cu"
		)
		(hatch none 0.5)
		(connect_pads
			(clearance 0)
		)
		(min_thickness 0.25)
		(keepout
			(tracks not_allowed)
			(vias allowed)
			(pads allowed)
			(copperpour not_allowed)
			(footprints allowed)
		)
		(placement
			(enabled no)
			(sheetname "")
		)
		(fill
			(thermal_gap 0.5)
			(thermal_bridge_width 0.5)
			(island_removal_mode 0)
		)
		(polygon
			(pts
				(arc
					(start 344.042746 -286.475424)
					(mid 343.384886 -286.475424)
					(end 344.042746 -286.475424)
				)
			)
		)
	)
	(zone
		(layers "F.Cu" "B.Cu" "In1.Cu" "In2.Cu" "In3.Cu" "In4.Cu" "In5.Cu" "In6.Cu"
			"In7.Cu" "In8.Cu" "In9.Cu" "In10.Cu" "In11.Cu" "In12.Cu" "In13.Cu" "In14.Cu"
			"In15.Cu" "In16.Cu"
		)
		(hatch none 0.5)
		(connect_pads
			(clearance 0)
		)
		(min_thickness 0.25)
		(keepout
			(tracks not_allowed)
			(vias allowed)
			(pads allowed)
			(copperpour not_allowed)
			(footprints allowed)
		)
		(placement
			(enabled no)
			(sheetname "")
		)
		(fill
			(thermal_gap 0.5)
			(thermal_bridge_width 0.5)
			(island_removal_mode 0)
		)
		(polygon
			(pts
				(arc
					(start 94.8944 -217.780108)
					(mid 94.822411 -217.707949)
					(end 94.723966 -217.681556)
				)
				(arc
					(start 94.723966 -217.681556)
					(mid 94.584772 -217.739212)
					(end 94.527116 -217.878406)
				)
				(arc
					(start 94.527116 -217.878406)
					(mid 94.533873 -217.929287)
					(end 94.553532 -217.976704)
				)
				(arc
					(start 95.023178 -218.79052)
					(mid 95.095167 -218.862679)
					(end 95.193612 -218.889072)
				)
				(arc
					(start 95.193612 -218.889072)
					(mid 95.332806 -218.831416)
					(end 95.390462 -218.692222)
				)
				(arc
					(start 95.390462 -218.692222)
					(mid 95.383705 -218.641341)
					(end 95.364046 -218.593924)
				)
			)
		)
	)
	(zone
		(layers "F.Cu" "B.Cu" "In1.Cu" "In2.Cu" "In3.Cu" "In4.Cu" "In5.Cu" "In6.Cu"
			"In7.Cu" "In8.Cu" "In9.Cu" "In10.Cu" "In11.Cu" "In12.Cu" "In13.Cu" "In14.Cu"
			"In15.Cu" "In16.Cu"
		)
		(hatch none 0.5)
		(connect_pads
			(clearance 0)
		)
		(min_thickness 0.25)
		(keepout
			(tracks not_allowed)
			(vias allowed)
			(pads allowed)
			(copperpour not_allowed)
			(footprints allowed)
		)
		(placement
			(enabled no)
			(sheetname "")
		)
		(fill
			(thermal_gap 0.5)
			(thermal_bridge_width 0.5)
			(island_removal_mode 0)
		)
		(polygon
			(pts
				(arc
					(start 381.164592 -285.661354)
					(mid 380.506732 -285.661354)
					(end 381.164592 -285.661354)
				)
			)
		)
	)
	(zone
		(layers "F.Cu" "B.Cu" "In1.Cu" "In2.Cu" "In3.Cu" "In4.Cu" "In5.Cu" "In6.Cu"
			"In7.Cu" "In8.Cu" "In9.Cu" "In10.Cu" "In11.Cu" "In12.Cu" "In13.Cu" "In14.Cu"
			"In15.Cu" "In16.Cu"
		)
		(hatch none 0.5)
		(connect_pads
			(clearance 0)
		)
		(min_thickness 0.25)
		(keepout
			(tracks not_allowed)
			(vias allowed)
			(pads allowed)
			(copperpour not_allowed)
			(footprints allowed)
		)
		(placement
			(enabled no)
			(sheetname "")
		)
		(fill
			(thermal_gap 0.5)
			(thermal_bridge_width 0.5)
			(island_removal_mode 0)
		)
		(polygon
			(pts
				(arc
					(start 355.991668 -217.780108)
					(mid 355.919679 -217.707949)
					(end 355.821234 -217.681556)
				)
				(arc
					(start 355.821234 -217.681556)
					(mid 355.68204 -217.739212)
					(end 355.624384 -217.878406)
				)
				(arc
					(start 355.624384 -217.878406)
					(mid 355.631141 -217.929287)
					(end 355.6508 -217.976704)
				)
				(arc
					(start 356.120446 -218.79052)
					(mid 356.192435 -218.862679)
					(end 356.29088 -218.889072)
				)
				(arc
					(start 356.29088 -218.889072)
					(mid 356.430074 -218.831416)
					(end 356.48773 -218.692222)
				)
				(arc
					(start 356.48773 -218.692222)
					(mid 356.480973 -218.641341)
					(end 356.461314 -218.593924)
				)
			)
		)
	)
	(zone
		(layers "F.Cu" "B.Cu" "In1.Cu" "In2.Cu" "In3.Cu" "In4.Cu" "In5.Cu" "In6.Cu"
			"In7.Cu" "In8.Cu" "In9.Cu" "In10.Cu" "In11.Cu" "In12.Cu" "In13.Cu" "In14.Cu"
			"In15.Cu" "In16.Cu"
		)
		(hatch none 0.5)
		(connect_pads
			(clearance 0)
		)
		(min_thickness 0.25)
		(keepout
			(tracks not_allowed)
			(vias allowed)
			(pads allowed)
			(copperpour not_allowed)
			(footprints allowed)
		)
		(placement
			(enabled no)
			(sheetname "")
		)
		(fill
			(thermal_gap 0.5)
			(thermal_bridge_width 0.5)
			(island_removal_mode 0)
		)
		(polygon
			(pts
				(arc
					(start 348.161864 -213.732618)
					(mid 347.504004 -213.732618)
					(end 348.161864 -213.732618)
				)
			)
		)
	)
	(zone
		(layers "F.Cu" "B.Cu" "In1.Cu" "In2.Cu" "In3.Cu" "In4.Cu" "In5.Cu" "In6.Cu"
			"In7.Cu" "In8.Cu" "In9.Cu" "In10.Cu" "In11.Cu" "In12.Cu" "In13.Cu" "In14.Cu"
			"In15.Cu" "In16.Cu"
		)
		(hatch none 0.5)
		(connect_pads
			(clearance 0)
		)
		(min_thickness 0.25)
		(keepout
			(tracks not_allowed)
			(vias allowed)
			(pads allowed)
			(copperpour not_allowed)
			(footprints allowed)
		)
		(placement
			(enabled no)
			(sheetname "")
		)
		(fill
			(thermal_gap 0.5)
			(thermal_bridge_width 0.5)
			(island_removal_mode 0)
		)
		(polygon
			(pts
				(arc
					(start 374.946164 -221.133924)
					(mid 374.288304 -221.133924)
					(end 374.946164 -221.133924)
				)
			)
		)
	)
	(zone
		(layers "F.Cu" "B.Cu" "In1.Cu" "In2.Cu" "In3.Cu" "In4.Cu" "In5.Cu" "In6.Cu"
			"In7.Cu" "In8.Cu" "In9.Cu" "In10.Cu" "In11.Cu" "In12.Cu" "In13.Cu" "In14.Cu"
			"In15.Cu" "In16.Cu"
		)
		(hatch none 0.5)
		(connect_pads
			(clearance 0)
		)
		(min_thickness 0.25)
		(keepout
			(tracks not_allowed)
			(vias allowed)
			(pads allowed)
			(copperpour not_allowed)
			(footprints allowed)
		)
		(placement
			(enabled no)
			(sheetname "")
		)
		(fill
			(thermal_gap 0.5)
			(thermal_bridge_width 0.5)
			(island_removal_mode 0)
		)
		(polygon
			(pts
				(arc
					(start 352.390964 -217.878406)
					(mid 351.733104 -217.878406)
					(end 352.390964 -217.878406)
				)
			)
		)
	)
	(zone
		(layers "F.Cu" "B.Cu" "In1.Cu" "In2.Cu" "In3.Cu" "In4.Cu" "In5.Cu" "In6.Cu"
			"In7.Cu" "In8.Cu" "In9.Cu" "In10.Cu" "In11.Cu" "In12.Cu" "In13.Cu" "In14.Cu"
			"In15.Cu" "In16.Cu"
		)
		(hatch none 0.5)
		(connect_pads
			(clearance 0)
		)
		(min_thickness 0.25)
		(keepout
			(tracks not_allowed)
			(vias allowed)
			(pads allowed)
			(copperpour not_allowed)
			(footprints allowed)
		)
		(placement
			(enabled no)
			(sheetname "")
		)
		(fill
			(thermal_gap 0.5)
			(thermal_bridge_width 0.5)
			(island_removal_mode 0)
		)
		(polygon
			(pts
				(arc
					(start 93.564964 -289.807142)
					(mid 94.222824 -289.807142)
					(end 93.564964 -289.807142)
				)
			)
		)
	)
	(zone
		(layers "F.Cu" "B.Cu" "In1.Cu" "In2.Cu" "In3.Cu" "In4.Cu" "In5.Cu" "In6.Cu"
			"In7.Cu" "In8.Cu" "In9.Cu" "In10.Cu" "In11.Cu" "In12.Cu" "In13.Cu" "In14.Cu"
			"In15.Cu" "In16.Cu"
		)
		(hatch none 0.5)
		(connect_pads
			(clearance 0)
		)
		(min_thickness 0.25)
		(keepout
			(tracks not_allowed)
			(vias allowed)
			(pads allowed)
			(copperpour not_allowed)
			(footprints allowed)
		)
		(placement
			(enabled no)
			(sheetname "")
		)
		(fill
			(thermal_gap 0.5)
			(thermal_bridge_width 0.5)
			(island_removal_mode 0)
		)
		(polygon
			(pts
				(arc
					(start 102.821994 -278.953468)
					(mid 102.625144 -279.150318)
					(end 102.821994 -279.347168)
				)
				(arc
					(start 103.761794 -279.347168)
					(mid 103.958644 -279.150318)
					(end 103.761794 -278.953468)
				)
			)
		)
	)
	(zone
		(layers "F.Cu" "B.Cu" "In1.Cu" "In2.Cu" "In3.Cu" "In4.Cu" "In5.Cu" "In6.Cu"
			"In7.Cu" "In8.Cu" "In9.Cu" "In10.Cu" "In11.Cu" "In12.Cu" "In13.Cu" "In14.Cu"
			"In15.Cu" "In16.Cu"
		)
		(hatch none 0.5)
		(connect_pads
			(clearance 0)
		)
		(min_thickness 0.25)
		(keepout
			(tracks not_allowed)
			(vias allowed)
			(pads allowed)
			(copperpour not_allowed)
			(footprints allowed)
		)
		(placement
			(enabled no)
			(sheetname "")
		)
		(fill
			(thermal_gap 0.5)
			(thermal_bridge_width 0.5)
			(island_removal_mode 0)
		)
		(polygon
			(pts
				(arc
					(start 116.509292 -221.231968)
					(mid 116.528976 -221.184558)
					(end 116.535708 -221.13367)
				)
				(arc
					(start 116.535708 -221.13367)
					(mid 116.478052 -220.994476)
					(end 116.338858 -220.93682)
				)
				(arc
					(start 116.338858 -220.93682)
					(mid 116.240427 -220.963236)
					(end 116.168424 -221.035372)
				)
				(arc
					(start 115.698778 -221.849442)
					(mid 115.679094 -221.896852)
					(end 115.672362 -221.94774)
				)
				(arc
					(start 115.672362 -221.94774)
					(mid 115.730018 -222.086934)
					(end 115.869212 -222.14459)
				)
				(arc
					(start 115.869212 -222.14459)
					(mid 115.967643 -222.118174)
					(end 116.039646 -222.046038)
				)
			)
		)
	)
	(zone
		(layers "F.Cu" "B.Cu" "In1.Cu" "In2.Cu" "In3.Cu" "In4.Cu" "In5.Cu" "In6.Cu"
			"In7.Cu" "In8.Cu" "In9.Cu" "In10.Cu" "In11.Cu" "In12.Cu" "In13.Cu" "In14.Cu"
			"In15.Cu" "In16.Cu"
		)
		(hatch none 0.5)
		(connect_pads
			(clearance 0)
		)
		(min_thickness 0.25)
		(keepout
			(tracks not_allowed)
			(vias allowed)
			(pads allowed)
			(copperpour not_allowed)
			(footprints allowed)
		)
		(placement
			(enabled no)
			(sheetname "")
		)
		(fill
			(thermal_gap 0.5)
			(thermal_bridge_width 0.5)
			(island_removal_mode 0)
		)
		(polygon
			(pts
				(arc
					(start 357.23068 -215.239854)
					(mid 357.03383 -215.436704)
					(end 357.23068 -215.633554)
				)
				(arc
					(start 358.17048 -215.633554)
					(mid 358.36733 -215.436704)
					(end 358.17048 -215.239854)
				)
			)
		)
	)
	(zone
		(layers "F.Cu" "B.Cu" "In1.Cu" "In2.Cu" "In3.Cu" "In4.Cu" "In5.Cu" "In6.Cu"
			"In7.Cu" "In8.Cu" "In9.Cu" "In10.Cu" "In11.Cu" "In12.Cu" "In13.Cu" "In14.Cu"
			"In15.Cu" "In16.Cu"
		)
		(hatch none 0.5)
		(connect_pads
			(clearance 0)
		)
		(min_thickness 0.25)
		(keepout
			(tracks not_allowed)
			(vias allowed)
			(pads allowed)
			(copperpour not_allowed)
			(footprints allowed)
		)
		(placement
			(enabled no)
			(sheetname "")
		)
		(fill
			(thermal_gap 0.5)
			(thermal_bridge_width 0.5)
			(island_removal_mode 0)
		)
		(polygon
			(pts
				(arc
					(start 92.232988 -214.622634)
					(mid 91.575128 -214.622634)
					(end 92.232988 -214.622634)
				)
			)
		)
	)
	(zone
		(layers "F.Cu" "B.Cu" "In1.Cu" "In2.Cu" "In3.Cu" "In4.Cu" "In5.Cu" "In6.Cu"
			"In7.Cu" "In8.Cu" "In9.Cu" "In10.Cu" "In11.Cu" "In12.Cu" "In13.Cu" "In14.Cu"
			"In15.Cu" "In16.Cu"
		)
		(hatch none 0.5)
		(connect_pads
			(clearance 0)
		)
		(min_thickness 0.25)
		(keepout
			(tracks not_allowed)
			(vias allowed)
			(pads allowed)
			(copperpour not_allowed)
			(footprints allowed)
		)
		(placement
			(enabled no)
			(sheetname "")
		)
		(fill
			(thermal_gap 0.5)
			(thermal_bridge_width 0.5)
			(island_removal_mode 0)
		)
		(polygon
			(pts
				(arc
					(start 102.101142 -217.064336)
					(mid 101.443282 -217.064336)
					(end 102.101142 -217.064336)
				)
			)
		)
	)
	(zone
		(layers "F.Cu" "B.Cu" "In1.Cu" "In2.Cu" "In3.Cu" "In4.Cu" "In5.Cu" "In6.Cu"
			"In7.Cu" "In8.Cu" "In9.Cu" "In10.Cu" "In11.Cu" "In12.Cu" "In13.Cu" "In14.Cu"
			"In15.Cu" "In16.Cu"
		)
		(hatch none 0.5)
		(connect_pads
			(clearance 0)
		)
		(min_thickness 0.25)
		(keepout
			(tracks not_allowed)
			(vias allowed)
			(pads allowed)
			(copperpour not_allowed)
			(footprints allowed)
		)
		(placement
			(enabled no)
			(sheetname "")
		)
		(fill
			(thermal_gap 0.5)
			(thermal_bridge_width 0.5)
			(island_removal_mode 0)
		)
		(polygon
			(pts
				(arc
					(start 109.290612 -215.239854)
					(mid 109.093762 -215.436704)
					(end 109.290612 -215.633554)
				)
				(arc
					(start 110.230412 -215.633554)
					(mid 110.427262 -215.436704)
					(end 110.230412 -215.239854)
				)
			)
		)
	)
	(zone
		(layers "F.Cu" "B.Cu" "In1.Cu" "In2.Cu" "In3.Cu" "In4.Cu" "In5.Cu" "In6.Cu"
			"In7.Cu" "In8.Cu" "In9.Cu" "In10.Cu" "In11.Cu" "In12.Cu" "In13.Cu" "In14.Cu"
			"In15.Cu" "In16.Cu"
		)
		(hatch none 0.5)
		(connect_pads
			(clearance 0)
		)
		(min_thickness 0.25)
		(keepout
			(tracks not_allowed)
			(vias allowed)
			(pads allowed)
			(copperpour not_allowed)
			(footprints allowed)
		)
		(placement
			(enabled no)
			(sheetname "")
		)
		(fill
			(thermal_gap 0.5)
			(thermal_bridge_width 0.5)
			(island_removal_mode 0)
		)
		(polygon
			(pts
				(arc
					(start 372.438422 -216.966292)
					(mid 372.366433 -216.894133)
					(end 372.267988 -216.86774)
				)
				(arc
					(start 372.267988 -216.86774)
					(mid 372.128794 -216.925396)
					(end 372.071138 -217.06459)
				)
				(arc
					(start 372.071138 -217.06459)
					(mid 372.077895 -217.115471)
					(end 372.097554 -217.162888)
				)
				(arc
					(start 372.5672 -217.976704)
					(mid 372.639189 -218.048863)
					(end 372.737634 -218.075256)
				)
				(arc
					(start 372.737634 -218.075256)
					(mid 372.876828 -218.0176)
					(end 372.934484 -217.878406)
				)
				(arc
					(start 372.934484 -217.878406)
					(mid 372.927727 -217.827525)
					(end 372.908068 -217.780108)
				)
			)
		)
	)
	(zone
		(layers "F.Cu" "B.Cu" "In1.Cu" "In2.Cu" "In3.Cu" "In4.Cu" "In5.Cu" "In6.Cu"
			"In7.Cu" "In8.Cu" "In9.Cu" "In10.Cu" "In11.Cu" "In12.Cu" "In13.Cu" "In14.Cu"
			"In15.Cu" "In16.Cu"
		)
		(hatch none 0.5)
		(connect_pads
			(clearance 0)
		)
		(min_thickness 0.25)
		(keepout
			(tracks not_allowed)
			(vias allowed)
			(pads allowed)
			(copperpour not_allowed)
			(footprints allowed)
		)
		(placement
			(enabled no)
			(sheetname "")
		)
		(fill
			(thermal_gap 0.5)
			(thermal_bridge_width 0.5)
			(island_removal_mode 0)
		)
		(polygon
			(pts
				(arc
					(start 104.920542 -221.94774)
					(mid 104.262682 -221.94774)
					(end 104.920542 -221.94774)
				)
			)
		)
	)
	(zone
		(layers "F.Cu" "B.Cu" "In1.Cu" "In2.Cu" "In3.Cu" "In4.Cu" "In5.Cu" "In6.Cu"
			"In7.Cu" "In8.Cu" "In9.Cu" "In10.Cu" "In11.Cu" "In12.Cu" "In13.Cu" "In14.Cu"
			"In15.Cu" "In16.Cu"
		)
		(hatch none 0.5)
		(connect_pads
			(clearance 0)
		)
		(min_thickness 0.25)
		(keepout
			(tracks not_allowed)
			(vias allowed)
			(pads allowed)
			(copperpour not_allowed)
			(footprints allowed)
		)
		(placement
			(enabled no)
			(sheetname "")
		)
		(fill
			(thermal_gap 0.5)
			(thermal_bridge_width 0.5)
			(island_removal_mode 0)
		)
		(polygon
			(pts
				(arc
					(start 339.343492 -288.103056)
					(mid 338.685632 -288.103056)
					(end 339.343492 -288.103056)
				)
			)
		)
	)
	(zone
		(layers "F.Cu" "B.Cu" "In1.Cu" "In2.Cu" "In3.Cu" "In4.Cu" "In5.Cu" "In6.Cu"
			"In7.Cu" "In8.Cu" "In9.Cu" "In10.Cu" "In11.Cu" "In12.Cu" "In13.Cu" "In14.Cu"
			"In15.Cu" "In16.Cu"
		)
		(hatch none 0.5)
		(connect_pads
			(clearance 0)
		)
		(min_thickness 0.25)
		(keepout
			(tracks not_allowed)
			(vias allowed)
			(pads allowed)
			(copperpour not_allowed)
			(footprints allowed)
		)
		(placement
			(enabled no)
			(sheetname "")
		)
		(fill
			(thermal_gap 0.5)
			(thermal_bridge_width 0.5)
			(island_removal_mode 0)
		)
		(polygon
			(pts
				(arc
					(start 129.344674 -403.502876)
					(mid 128.963674 -403.883876)
					(end 129.344674 -404.264876)
				)
				(arc
					(start 130.208274 -404.264876)
					(mid 130.589274 -403.883876)
					(end 130.208274 -403.502876)
				)
			)
		)
	)
	(zone
		(layers "F.Cu" "B.Cu" "In1.Cu" "In2.Cu" "In3.Cu" "In4.Cu" "In5.Cu" "In6.Cu"
			"In7.Cu" "In8.Cu" "In9.Cu" "In10.Cu" "In11.Cu" "In12.Cu" "In13.Cu" "In14.Cu"
			"In15.Cu" "In16.Cu"
		)
		(hatch none 0.5)
		(connect_pads
			(clearance 0)
		)
		(min_thickness 0.25)
		(keepout
			(tracks not_allowed)
			(vias allowed)
			(pads allowed)
			(copperpour not_allowed)
			(footprints allowed)
		)
		(placement
			(enabled no)
			(sheetname "")
		)
		(fill
			(thermal_gap 0.5)
			(thermal_bridge_width 0.5)
			(island_removal_mode 0)
		)
		(polygon
			(pts
				(arc
					(start 96.854264 -280.778204)
					(mid 97.512124 -280.778204)
					(end 96.854264 -280.778204)
				)
			)
		)
	)
	(zone
		(layers "F.Cu" "B.Cu" "In1.Cu" "In2.Cu" "In3.Cu" "In4.Cu" "In5.Cu" "In6.Cu"
			"In7.Cu" "In8.Cu" "In9.Cu" "In10.Cu" "In11.Cu" "In12.Cu" "In13.Cu" "In14.Cu"
			"In15.Cu" "In16.Cu"
		)
		(hatch none 0.5)
		(connect_pads
			(clearance 0)
		)
		(min_thickness 0.25)
		(keepout
			(tracks not_allowed)
			(vias allowed)
			(pads allowed)
			(copperpour not_allowed)
			(footprints allowed)
		)
		(placement
			(enabled no)
			(sheetname "")
		)
		(fill
			(thermal_gap 0.5)
			(thermal_bridge_width 0.5)
			(island_removal_mode 0)
		)
		(polygon
			(pts
				(arc
					(start 26.21661 -6.343396)
					(mid 25.83561 -6.724396)
					(end 26.21661 -7.105396)
				)
				(arc
					(start 27.08021 -7.105396)
					(mid 27.46121 -6.724396)
					(end 27.08021 -6.343396)
				)
			)
		)
	)
	(zone
		(layers "F.Cu" "B.Cu" "In1.Cu" "In2.Cu" "In3.Cu" "In4.Cu" "In5.Cu" "In6.Cu"
			"In7.Cu" "In8.Cu" "In9.Cu" "In10.Cu" "In11.Cu" "In12.Cu" "In13.Cu" "In14.Cu"
			"In15.Cu" "In16.Cu"
		)
		(hatch none 0.5)
		(connect_pads
			(clearance 0)
		)
		(min_thickness 0.25)
		(keepout
			(tracks not_allowed)
			(vias allowed)
			(pads allowed)
			(copperpour not_allowed)
			(footprints allowed)
		)
		(placement
			(enabled no)
			(sheetname "")
		)
		(fill
			(thermal_gap 0.5)
			(thermal_bridge_width 0.5)
			(island_removal_mode 0)
		)
		(polygon
			(pts
				(arc
					(start 340.484714 -220.418152)
					(mid 340.504398 -220.370742)
					(end 340.51113 -220.319854)
				)
				(arc
					(start 340.51113 -220.319854)
					(mid 340.453474 -220.18066)
					(end 340.31428 -220.123004)
				)
				(arc
					(start 340.31428 -220.123004)
					(mid 340.215849 -220.14942)
					(end 340.143846 -220.221556)
				)
				(arc
					(start 339.6742 -221.035626)
					(mid 339.654516 -221.083036)
					(end 339.647784 -221.133924)
				)
				(arc
					(start 339.647784 -221.133924)
					(mid 339.70544 -221.273118)
					(end 339.844634 -221.330774)
				)
				(arc
					(start 339.844634 -221.330774)
					(mid 339.943065 -221.304358)
					(end 340.015068 -221.232222)
				)
			)
		)
	)
	(zone
		(layers "F.Cu" "B.Cu" "In1.Cu" "In2.Cu" "In3.Cu" "In4.Cu" "In5.Cu" "In6.Cu"
			"In7.Cu" "In8.Cu" "In9.Cu" "In10.Cu" "In11.Cu" "In12.Cu" "In13.Cu" "In14.Cu"
			"In15.Cu" "In16.Cu"
		)
		(hatch none 0.5)
		(connect_pads
			(clearance 0)
		)
		(min_thickness 0.25)
		(keepout
			(tracks not_allowed)
			(vias allowed)
			(pads allowed)
			(copperpour not_allowed)
			(footprints allowed)
		)
		(placement
			(enabled no)
			(sheetname "")
		)
		(fill
			(thermal_gap 0.5)
			(thermal_bridge_width 0.5)
			(island_removal_mode 0)
		)
		(polygon
			(pts
				(arc
					(start 353.440746 -283.219906)
					(mid 352.782886 -283.219906)
					(end 353.440746 -283.219906)
				)
			)
		)
	)
	(zone
		(layers "F.Cu" "B.Cu" "In1.Cu" "In2.Cu" "In3.Cu" "In4.Cu" "In5.Cu" "In6.Cu"
			"In7.Cu" "In8.Cu" "In9.Cu" "In10.Cu" "In11.Cu" "In12.Cu" "In13.Cu" "In14.Cu"
			"In15.Cu" "In16.Cu"
		)
		(hatch none 0.5)
		(connect_pads
			(clearance 0)
		)
		(min_thickness 0.25)
		(keepout
			(tracks not_allowed)
			(vias allowed)
			(pads allowed)
			(copperpour not_allowed)
			(footprints allowed)
		)
		(placement
			(enabled no)
			(sheetname "")
		)
		(fill
			(thermal_gap 0.5)
			(thermal_bridge_width 0.5)
			(island_removal_mode 0)
		)
		(polygon
			(pts
				(arc
					(start 103.352092 -214.720932)
					(mid 103.371776 -214.673522)
					(end 103.378508 -214.622634)
				)
				(arc
					(start 103.378508 -214.622634)
					(mid 103.320852 -214.48344)
					(end 103.181658 -214.425784)
				)
				(arc
					(start 103.181658 -214.425784)
					(mid 103.083227 -214.4522)
					(end 103.011224 -214.524336)
				)
				(arc
					(start 102.541578 -215.338406)
					(mid 102.521894 -215.385816)
					(end 102.515162 -215.436704)
				)
				(arc
					(start 102.515162 -215.436704)
					(mid 102.572818 -215.575898)
					(end 102.712012 -215.633554)
				)
				(arc
					(start 102.712012 -215.633554)
					(mid 102.810443 -215.607138)
					(end 102.882446 -215.535002)
				)
			)
		)
	)
	(zone
		(layers "F.Cu" "B.Cu" "In1.Cu" "In2.Cu" "In3.Cu" "In4.Cu" "In5.Cu" "In6.Cu"
			"In7.Cu" "In8.Cu" "In9.Cu" "In10.Cu" "In11.Cu" "In12.Cu" "In13.Cu" "In14.Cu"
			"In15.Cu" "In16.Cu"
		)
		(hatch none 0.5)
		(connect_pads
			(clearance 0)
		)
		(min_thickness 0.25)
		(keepout
			(tracks not_allowed)
			(vias allowed)
			(pads allowed)
			(copperpour not_allowed)
			(footprints allowed)
		)
		(placement
			(enabled no)
			(sheetname "")
		)
		(fill
			(thermal_gap 0.5)
			(thermal_bridge_width 0.5)
			(island_removal_mode 0)
		)
		(polygon
			(pts
				(arc
					(start 385.02209 -409.649168)
					(mid 384.64109 -410.030168)
					(end 385.02209 -410.411168)
				)
				(arc
					(start 385.88569 -410.411168)
					(mid 386.26669 -410.030168)
					(end 385.88569 -409.649168)
				)
			)
		)
	)
	(zone
		(layers "F.Cu" "B.Cu" "In1.Cu" "In2.Cu" "In3.Cu" "In4.Cu" "In5.Cu" "In6.Cu"
			"In7.Cu" "In8.Cu" "In9.Cu" "In10.Cu" "In11.Cu" "In12.Cu" "In13.Cu" "In14.Cu"
			"In15.Cu" "In16.Cu"
		)
		(hatch none 0.5)
		(connect_pads
			(clearance 0)
		)
		(min_thickness 0.25)
		(keepout
			(tracks not_allowed)
			(vias allowed)
			(pads allowed)
			(copperpour not_allowed)
			(footprints allowed)
		)
		(placement
			(enabled no)
			(sheetname "")
		)
		(fill
			(thermal_gap 0.5)
			(thermal_bridge_width 0.5)
			(island_removal_mode 0)
		)
		(polygon
			(pts
				(arc
					(start 382.104646 -288.917126)
					(mid 381.446786 -288.917126)
					(end 382.104646 -288.917126)
				)
			)
		)
	)
	(zone
		(layers "F.Cu" "B.Cu" "In1.Cu" "In2.Cu" "In3.Cu" "In4.Cu" "In5.Cu" "In6.Cu"
			"In7.Cu" "In8.Cu" "In9.Cu" "In10.Cu" "In11.Cu" "In12.Cu" "In13.Cu" "In14.Cu"
			"In15.Cu" "In16.Cu"
		)
		(hatch none 0.5)
		(connect_pads
			(clearance 0)
		)
		(min_thickness 0.25)
		(keepout
			(tracks not_allowed)
			(vias allowed)
			(pads allowed)
			(copperpour not_allowed)
			(footprints allowed)
		)
		(placement
			(enabled no)
			(sheetname "")
		)
		(fill
			(thermal_gap 0.5)
			(thermal_bridge_width 0.5)
			(island_removal_mode 0)
		)
		(polygon
			(pts
				(arc
					(start 382.464564 -221.133924)
					(mid 381.806704 -221.133924)
					(end 382.464564 -221.133924)
				)
			)
		)
	)
	(zone
		(layers "F.Cu" "B.Cu" "In1.Cu" "In2.Cu" "In3.Cu" "In4.Cu" "In5.Cu" "In6.Cu"
			"In7.Cu" "In8.Cu" "In9.Cu" "In10.Cu" "In11.Cu" "In12.Cu" "In13.Cu" "In14.Cu"
			"In15.Cu" "In16.Cu"
		)
		(hatch none 0.5)
		(connect_pads
			(clearance 0)
		)
		(min_thickness 0.25)
		(keepout
			(tracks not_allowed)
			(vias allowed)
			(pads allowed)
			(copperpour not_allowed)
			(footprints allowed)
		)
		(placement
			(enabled no)
			(sheetname "")
		)
		(fill
			(thermal_gap 0.5)
			(thermal_bridge_width 0.5)
			(island_removal_mode 0)
		)
		(polygon
			(pts
				(arc
					(start 356.61981 -218.692222)
					(mid 355.96195 -218.692222)
					(end 356.61981 -218.692222)
				)
			)
		)
	)
	(zone
		(layers "F.Cu" "B.Cu" "In1.Cu" "In2.Cu" "In3.Cu" "In4.Cu" "In5.Cu" "In6.Cu"
			"In7.Cu" "In8.Cu" "In9.Cu" "In10.Cu" "In11.Cu" "In12.Cu" "In13.Cu" "In14.Cu"
			"In15.Cu" "In16.Cu"
		)
		(hatch none 0.5)
		(connect_pads
			(clearance 0)
		)
		(min_thickness 0.25)
		(keepout
			(tracks not_allowed)
			(vias allowed)
			(pads allowed)
			(copperpour not_allowed)
			(footprints allowed)
		)
		(placement
			(enabled no)
			(sheetname "")
		)
		(fill
			(thermal_gap 0.5)
			(thermal_bridge_width 0.5)
			(island_removal_mode 0)
		)
		(polygon
			(pts
				(arc
					(start 372.76913 -409.649168)
					(mid 372.38813 -410.030168)
					(end 372.76913 -410.411168)
				)
				(arc
					(start 373.63273 -410.411168)
					(mid 374.01373 -410.030168)
					(end 373.63273 -409.649168)
				)
			)
		)
	)
	(zone
		(layers "F.Cu" "B.Cu" "In1.Cu" "In2.Cu" "In3.Cu" "In4.Cu" "In5.Cu" "In6.Cu"
			"In7.Cu" "In8.Cu" "In9.Cu" "In10.Cu" "In11.Cu" "In12.Cu" "In13.Cu" "In14.Cu"
			"In15.Cu" "In16.Cu"
		)
		(hatch none 0.5)
		(connect_pads
			(clearance 0)
		)
		(min_thickness 0.25)
		(keepout
			(tracks not_allowed)
			(vias allowed)
			(pads allowed)
			(copperpour not_allowed)
			(footprints allowed)
		)
		(placement
			(enabled no)
			(sheetname "")
		)
		(fill
			(thermal_gap 0.5)
			(thermal_bridge_width 0.5)
			(island_removal_mode 0)
		)
		(polygon
			(pts
				(arc
					(start 126.957836 -288.005012)
					(mid 126.885847 -287.932853)
					(end 126.787402 -287.90646)
				)
				(arc
					(start 126.787402 -287.90646)
					(mid 126.648208 -287.964116)
					(end 126.590552 -288.10331)
				)
				(arc
					(start 126.590552 -288.10331)
					(mid 126.597309 -288.154191)
					(end 126.616968 -288.201608)
				)
				(arc
					(start 127.086614 -289.015424)
					(mid 127.158603 -289.087583)
					(end 127.257048 -289.113976)
				)
				(arc
					(start 127.257048 -289.113976)
					(mid 127.396242 -289.05632)
					(end 127.453898 -288.917126)
				)
				(arc
					(start 127.453898 -288.917126)
					(mid 127.447141 -288.866245)
					(end 127.427482 -288.818828)
				)
			)
		)
	)
	(zone
		(layers "F.Cu" "B.Cu" "In1.Cu" "In2.Cu" "In3.Cu" "In4.Cu" "In5.Cu" "In6.Cu"
			"In7.Cu" "In8.Cu" "In9.Cu" "In10.Cu" "In11.Cu" "In12.Cu" "In13.Cu" "In14.Cu"
			"In15.Cu" "In16.Cu"
		)
		(hatch none 0.5)
		(connect_pads
			(clearance 0)
		)
		(min_thickness 0.25)
		(keepout
			(tracks not_allowed)
			(vias allowed)
			(pads allowed)
			(copperpour not_allowed)
			(footprints allowed)
		)
		(placement
			(enabled no)
			(sheetname "")
		)
		(fill
			(thermal_gap 0.5)
			(thermal_bridge_width 0.5)
			(island_removal_mode 0)
		)
		(polygon
			(pts
				(arc
					(start 127.627634 -409.649168)
					(mid 127.246634 -410.030168)
					(end 127.627634 -410.411168)
				)
				(arc
					(start 128.491234 -410.411168)
					(mid 128.872234 -410.030168)
					(end 128.491234 -409.649168)
				)
			)
		)
	)
	(zone
		(layers "F.Cu" "B.Cu" "In1.Cu" "In2.Cu" "In3.Cu" "In4.Cu" "In5.Cu" "In6.Cu"
			"In7.Cu" "In8.Cu" "In9.Cu" "In10.Cu" "In11.Cu" "In12.Cu" "In13.Cu" "In14.Cu"
			"In15.Cu" "In16.Cu"
		)
		(hatch none 0.5)
		(connect_pads
			(clearance 0)
		)
		(min_thickness 0.25)
		(keepout
			(tracks not_allowed)
			(vias allowed)
			(pads allowed)
			(copperpour not_allowed)
			(footprints allowed)
		)
		(placement
			(enabled no)
			(sheetname "")
		)
		(fill
			(thermal_gap 0.5)
			(thermal_bridge_width 0.5)
			(island_removal_mode 0)
		)
		(polygon
			(pts
				(arc
					(start 359.280714 -217.162634)
					(mid 359.300398 -217.115224)
					(end 359.30713 -217.064336)
				)
				(arc
					(start 359.30713 -217.064336)
					(mid 359.249474 -216.925142)
					(end 359.11028 -216.867486)
				)
				(arc
					(start 359.11028 -216.867486)
					(mid 359.011849 -216.893902)
					(end 358.939846 -216.966038)
				)
				(arc
					(start 358.4702 -217.780108)
					(mid 358.450516 -217.827518)
					(end 358.443784 -217.878406)
				)
				(arc
					(start 358.443784 -217.878406)
					(mid 358.50144 -218.0176)
					(end 358.640634 -218.075256)
				)
				(arc
					(start 358.640634 -218.075256)
					(mid 358.739065 -218.04884)
					(end 358.811068 -217.976704)
				)
			)
		)
	)
	(zone
		(layers "F.Cu" "B.Cu" "In1.Cu" "In2.Cu" "In3.Cu" "In4.Cu" "In5.Cu" "In6.Cu"
			"In7.Cu" "In8.Cu" "In9.Cu" "In10.Cu" "In11.Cu" "In12.Cu" "In13.Cu" "In14.Cu"
			"In15.Cu" "In16.Cu"
		)
		(hatch none 0.5)
		(connect_pads
			(clearance 0)
		)
		(min_thickness 0.25)
		(keepout
			(tracks not_allowed)
			(vias allowed)
			(pads allowed)
			(copperpour not_allowed)
			(footprints allowed)
		)
		(placement
			(enabled no)
			(sheetname "")
		)
		(fill
			(thermal_gap 0.5)
			(thermal_bridge_width 0.5)
			(island_removal_mode 0)
		)
		(polygon
			(pts
				(arc
					(start 167.449754 -406.62352)
					(mid 167.068754 -407.00452)
					(end 167.449754 -407.38552)
				)
				(arc
					(start 168.313354 -407.38552)
					(mid 168.694354 -407.00452)
					(end 168.313354 -406.62352)
				)
			)
		)
	)
	(zone
		(layers "F.Cu" "B.Cu" "In1.Cu" "In2.Cu" "In3.Cu" "In4.Cu" "In5.Cu" "In6.Cu"
			"In7.Cu" "In8.Cu" "In9.Cu" "In10.Cu" "In11.Cu" "In12.Cu" "In13.Cu" "In14.Cu"
			"In15.Cu" "In16.Cu"
		)
		(hatch none 0.5)
		(connect_pads
			(clearance 0)
		)
		(min_thickness 0.25)
		(keepout
			(tracks not_allowed)
			(vias allowed)
			(pads allowed)
			(copperpour not_allowed)
			(footprints allowed)
		)
		(placement
			(enabled no)
			(sheetname "")
		)
		(fill
			(thermal_gap 0.5)
			(thermal_bridge_width 0.5)
			(island_removal_mode 0)
		)
		(polygon
			(pts
				(arc
					(start 340.643464 -213.732618)
					(mid 339.985604 -213.732618)
					(end 340.643464 -213.732618)
				)
			)
		)
	)
	(zone
		(layers "F.Cu" "B.Cu" "In1.Cu" "In2.Cu" "In3.Cu" "In4.Cu" "In5.Cu" "In6.Cu"
			"In7.Cu" "In8.Cu" "In9.Cu" "In10.Cu" "In11.Cu" "In12.Cu" "In13.Cu" "In14.Cu"
			"In15.Cu" "In16.Cu"
		)
		(hatch none 0.5)
		(connect_pads
			(clearance 0)
		)
		(min_thickness 0.25)
		(keepout
			(tracks not_allowed)
			(vias allowed)
			(pads allowed)
			(copperpour not_allowed)
			(footprints allowed)
		)
		(placement
			(enabled no)
			(sheetname "")
		)
		(fill
			(thermal_gap 0.5)
			(thermal_bridge_width 0.5)
			(island_removal_mode 0)
		)
		(polygon
			(pts
				(arc
					(start 112.909096 -217.878406)
					(mid 112.251236 -217.878406)
					(end 112.909096 -217.878406)
				)
			)
		)
	)
	(zone
		(layers "F.Cu" "B.Cu" "In1.Cu" "In2.Cu" "In3.Cu" "In4.Cu" "In5.Cu" "In6.Cu"
			"In7.Cu" "In8.Cu" "In9.Cu" "In10.Cu" "In11.Cu" "In12.Cu" "In13.Cu" "In14.Cu"
			"In15.Cu" "In16.Cu"
		)
		(hatch none 0.5)
		(connect_pads
			(clearance 0)
		)
		(min_thickness 0.25)
		(keepout
			(tracks not_allowed)
			(vias allowed)
			(pads allowed)
			(copperpour not_allowed)
			(footprints allowed)
		)
		(placement
			(enabled no)
			(sheetname "")
		)
		(fill
			(thermal_gap 0.5)
			(thermal_bridge_width 0.5)
			(island_removal_mode 0)
		)
		(polygon
			(pts
				(arc
					(start 121.836942 -225.203258)
					(mid 121.179082 -225.203258)
					(end 121.836942 -225.203258)
				)
			)
		)
	)
	(zone
		(layers "F.Cu" "B.Cu" "In1.Cu" "In2.Cu" "In3.Cu" "In4.Cu" "In5.Cu" "In6.Cu"
			"In7.Cu" "In8.Cu" "In9.Cu" "In10.Cu" "In11.Cu" "In12.Cu" "In13.Cu" "In14.Cu"
			"In15.Cu" "In16.Cu"
		)
		(hatch none 0.5)
		(connect_pads
			(clearance 0)
		)
		(min_thickness 0.25)
		(keepout
			(tracks not_allowed)
			(vias allowed)
			(pads allowed)
			(copperpour not_allowed)
			(footprints allowed)
		)
		(placement
			(enabled no)
			(sheetname "")
		)
		(fill
			(thermal_gap 0.5)
			(thermal_bridge_width 0.5)
			(island_removal_mode 0)
		)
		(polygon
			(pts
				(arc
					(start 374.831356 -182.750968)
					(mid 375.190566 -182.602178)
					(end 375.339356 -182.242968)
				)
				(arc
					(start 375.339356 -182.242968)
					(mid 375.271299 -181.988971)
					(end 375.085356 -181.80304)
				)
				(arc
					(start 374.161304 -181.269386)
					(mid 374.03901 -181.218849)
					(end 373.907812 -181.201568)
				)
				(arc
					(start 373.907304 -181.201568)
					(mid 373.548094 -181.350358)
					(end 373.399304 -181.709568)
				)
				(arc
					(start 373.399304 -181.709568)
					(mid 373.467361 -181.963565)
					(end 373.653304 -182.149496)
				)
				(arc
					(start 374.577356 -182.68315)
					(mid 374.69965 -182.733687)
					(end 374.830848 -182.750968)
				)
			)
		)
	)
	(zone
		(layers "F.Cu" "B.Cu" "In1.Cu" "In2.Cu" "In3.Cu" "In4.Cu" "In5.Cu" "In6.Cu"
			"In7.Cu" "In8.Cu" "In9.Cu" "In10.Cu" "In11.Cu" "In12.Cu" "In13.Cu" "In14.Cu"
			"In15.Cu" "In16.Cu"
		)
		(hatch none 0.5)
		(connect_pads
			(clearance 0)
		)
		(min_thickness 0.25)
		(keepout
			(tracks not_allowed)
			(vias allowed)
			(pads allowed)
			(copperpour not_allowed)
			(footprints allowed)
		)
		(placement
			(enabled no)
			(sheetname "")
		)
		(fill
			(thermal_gap 0.5)
			(thermal_bridge_width 0.5)
			(island_removal_mode 0)
		)
		(polygon
			(pts
				(arc
					(start 125.126496 -221.133924)
					(mid 124.468636 -221.133924)
					(end 125.126496 -221.133924)
				)
			)
		)
	)
	(zone
		(layers "F.Cu" "B.Cu" "In1.Cu" "In2.Cu" "In3.Cu" "In4.Cu" "In5.Cu" "In6.Cu"
			"In7.Cu" "In8.Cu" "In9.Cu" "In10.Cu" "In11.Cu" "In12.Cu" "In13.Cu" "In14.Cu"
			"In15.Cu" "In16.Cu"
		)
		(hatch none 0.5)
		(connect_pads
			(clearance 0)
		)
		(min_thickness 0.25)
		(keepout
			(tracks not_allowed)
			(vias allowed)
			(pads allowed)
			(copperpour not_allowed)
			(footprints allowed)
		)
		(placement
			(enabled no)
			(sheetname "")
		)
		(fill
			(thermal_gap 0.5)
			(thermal_bridge_width 0.5)
			(island_removal_mode 0)
		)
		(polygon
			(pts
				(arc
					(start 369.148868 -224.291144)
					(mid 369.076879 -224.218985)
					(end 368.978434 -224.192592)
				)
				(arc
					(start 368.978434 -224.192592)
					(mid 368.83924 -224.250248)
					(end 368.781584 -224.389442)
				)
				(arc
					(start 368.781584 -224.389442)
					(mid 368.788341 -224.440323)
					(end 368.808 -224.48774)
				)
				(arc
					(start 369.277646 -225.301556)
					(mid 369.349635 -225.373715)
					(end 369.44808 -225.400108)
				)
				(arc
					(start 369.44808 -225.400108)
					(mid 369.587274 -225.342452)
					(end 369.64493 -225.203258)
				)
				(arc
					(start 369.64493 -225.203258)
					(mid 369.638173 -225.152377)
					(end 369.618514 -225.10496)
				)
			)
		)
	)
	(zone
		(layers "F.Cu" "B.Cu" "In1.Cu" "In2.Cu" "In3.Cu" "In4.Cu" "In5.Cu" "In6.Cu"
			"In7.Cu" "In8.Cu" "In9.Cu" "In10.Cu" "In11.Cu" "In12.Cu" "In13.Cu" "In14.Cu"
			"In15.Cu" "In16.Cu"
		)
		(hatch none 0.5)
		(connect_pads
			(clearance 0)
		)
		(min_thickness 0.25)
		(keepout
			(tracks not_allowed)
			(vias allowed)
			(pads allowed)
			(copperpour not_allowed)
			(footprints allowed)
		)
		(placement
			(enabled no)
			(sheetname "")
		)
		(fill
			(thermal_gap 0.5)
			(thermal_bridge_width 0.5)
			(island_removal_mode 0)
		)
		(polygon
			(pts
				(arc
					(start 97.982278 -281.59202)
					(mid 97.324418 -281.59202)
					(end 97.982278 -281.59202)
				)
			)
		)
	)
	(zone
		(layers "F.Cu" "B.Cu" "In1.Cu" "In2.Cu" "In3.Cu" "In4.Cu" "In5.Cu" "In6.Cu"
			"In7.Cu" "In8.Cu" "In9.Cu" "In10.Cu" "In11.Cu" "In12.Cu" "In13.Cu" "In14.Cu"
			"In15.Cu" "In16.Cu"
		)
		(hatch none 0.5)
		(connect_pads
			(clearance 0)
		)
		(min_thickness 0.25)
		(keepout
			(tracks not_allowed)
			(vias allowed)
			(pads allowed)
			(copperpour not_allowed)
			(footprints allowed)
		)
		(placement
			(enabled no)
			(sheetname "")
		)
		(fill
			(thermal_gap 0.5)
			(thermal_bridge_width 0.5)
			(island_removal_mode 0)
		)
		(polygon
			(pts
				(arc
					(start 121.366788 -214.622634)
					(mid 120.708928 -214.622634)
					(end 121.366788 -214.622634)
				)
			)
		)
	)
	(zone
		(layers "F.Cu" "B.Cu" "In1.Cu" "In2.Cu" "In3.Cu" "In4.Cu" "In5.Cu" "In6.Cu"
			"In7.Cu" "In8.Cu" "In9.Cu" "In10.Cu" "In11.Cu" "In12.Cu" "In13.Cu" "In14.Cu"
			"In15.Cu" "In16.Cu"
		)
		(hatch none 0.5)
		(connect_pads
			(clearance 0)
		)
		(min_thickness 0.25)
		(keepout
			(tracks not_allowed)
			(vias allowed)
			(pads allowed)
			(copperpour not_allowed)
			(footprints allowed)
		)
		(placement
			(enabled no)
			(sheetname "")
		)
		(fill
			(thermal_gap 0.5)
			(thermal_bridge_width 0.5)
			(island_removal_mode 0)
		)
		(polygon
			(pts
				(arc
					(start 336.054192 -282.405836)
					(mid 335.396332 -282.405836)
					(end 336.054192 -282.405836)
				)
			)
		)
	)
	(zone
		(layers "F.Cu" "B.Cu" "In1.Cu" "In2.Cu" "In3.Cu" "In4.Cu" "In5.Cu" "In6.Cu"
			"In7.Cu" "In8.Cu" "In9.Cu" "In10.Cu" "In11.Cu" "In12.Cu" "In13.Cu" "In14.Cu"
			"In15.Cu" "In16.Cu"
		)
		(hatch none 0.5)
		(connect_pads
			(clearance 0)
		)
		(min_thickness 0.25)
		(keepout
			(tracks not_allowed)
			(vias allowed)
			(pads allowed)
			(copperpour not_allowed)
			(footprints allowed)
		)
		(placement
			(enabled no)
			(sheetname "")
		)
		(fill
			(thermal_gap 0.5)
			(thermal_bridge_width 0.5)
			(island_removal_mode 0)
		)
		(polygon
			(pts
				(arc
					(start 368.367564 -224.389442)
					(mid 367.709704 -224.389442)
					(end 368.367564 -224.389442)
				)
			)
		)
	)
	(zone
		(layers "F.Cu" "B.Cu" "In1.Cu" "In2.Cu" "In3.Cu" "In4.Cu" "In5.Cu" "In6.Cu"
			"In7.Cu" "In8.Cu" "In9.Cu" "In10.Cu" "In11.Cu" "In12.Cu" "In13.Cu" "In14.Cu"
			"In15.Cu" "In16.Cu"
		)
		(hatch none 0.5)
		(connect_pads
			(clearance 0)
		)
		(min_thickness 0.25)
		(keepout
			(tracks not_allowed)
			(vias allowed)
			(pads allowed)
			(copperpour not_allowed)
			(footprints allowed)
		)
		(placement
			(enabled no)
			(sheetname "")
		)
		(fill
			(thermal_gap 0.5)
			(thermal_bridge_width 0.5)
			(island_removal_mode 0)
		)
		(polygon
			(pts
				(arc
					(start 352.362516 -65.329562)
					(mid 352.743516 -65.710562)
					(end 353.124516 -65.329562)
				)
				(arc
					(start 353.124516 -64.465962)
					(mid 352.743516 -64.084962)
					(end 352.362516 -64.465962)
				)
			)
		)
	)
	(zone
		(layers "F.Cu" "B.Cu" "In1.Cu" "In2.Cu" "In3.Cu" "In4.Cu" "In5.Cu" "In6.Cu"
			"In7.Cu" "In8.Cu" "In9.Cu" "In10.Cu" "In11.Cu" "In12.Cu" "In13.Cu" "In14.Cu"
			"In15.Cu" "In16.Cu"
		)
		(hatch none 0.5)
		(connect_pads
			(clearance 0)
		)
		(min_thickness 0.25)
		(keepout
			(tracks not_allowed)
			(vias allowed)
			(pads allowed)
			(copperpour not_allowed)
			(footprints allowed)
		)
		(placement
			(enabled no)
			(sheetname "")
		)
		(fill
			(thermal_gap 0.5)
			(thermal_bridge_width 0.5)
			(island_removal_mode 0)
		)
		(polygon
			(pts
				(arc
					(start 337.82381 -221.94774)
					(mid 337.16595 -221.94774)
					(end 337.82381 -221.94774)
				)
			)
		)
	)
	(zone
		(layers "F.Cu" "B.Cu" "In1.Cu" "In2.Cu" "In3.Cu" "In4.Cu" "In5.Cu" "In6.Cu"
			"In7.Cu" "In8.Cu" "In9.Cu" "In10.Cu" "In11.Cu" "In12.Cu" "In13.Cu" "In14.Cu"
			"In15.Cu" "In16.Cu"
		)
		(hatch none 0.5)
		(connect_pads
			(clearance 0)
		)
		(min_thickness 0.25)
		(keepout
			(tracks not_allowed)
			(vias allowed)
			(pads allowed)
			(copperpour not_allowed)
			(footprints allowed)
		)
		(placement
			(enabled no)
			(sheetname "")
		)
		(fill
			(thermal_gap 0.5)
			(thermal_bridge_width 0.5)
			(island_removal_mode 0)
		)
		(polygon
			(pts
				(arc
					(start 58.515758 -409.649168)
					(mid 58.134758 -410.030168)
					(end 58.515758 -410.411168)
				)
				(arc
					(start 59.379358 -410.411168)
					(mid 59.760358 -410.030168)
					(end 59.379358 -409.649168)
				)
			)
		)
	)
	(zone
		(layers "F.Cu" "B.Cu" "In1.Cu" "In2.Cu" "In3.Cu" "In4.Cu" "In5.Cu" "In6.Cu"
			"In7.Cu" "In8.Cu" "In9.Cu" "In10.Cu" "In11.Cu" "In12.Cu" "In13.Cu" "In14.Cu"
			"In15.Cu" "In16.Cu"
		)
		(hatch none 0.5)
		(connect_pads
			(clearance 0)
		)
		(min_thickness 0.25)
		(keepout
			(tracks not_allowed)
			(vias allowed)
			(pads allowed)
			(copperpour not_allowed)
			(footprints allowed)
		)
		(placement
			(enabled no)
			(sheetname "")
		)
		(fill
			(thermal_gap 0.5)
			(thermal_bridge_width 0.5)
			(island_removal_mode 0)
		)
		(polygon
			(pts
				(arc
					(start 90.665046 -220.418152)
					(mid 90.68473 -220.370742)
					(end 90.691462 -220.319854)
				)
				(arc
					(start 90.691462 -220.319854)
					(mid 90.633806 -220.18066)
					(end 90.494612 -220.123004)
				)
				(arc
					(start 90.494612 -220.123004)
					(mid 90.396181 -220.14942)
					(end 90.324178 -220.221556)
				)
				(arc
					(start 89.854532 -221.035626)
					(mid 89.834848 -221.083036)
					(end 89.828116 -221.133924)
				)
				(arc
					(start 89.828116 -221.133924)
					(mid 89.885772 -221.273118)
					(end 90.024966 -221.330774)
				)
				(arc
					(start 90.024966 -221.330774)
					(mid 90.123397 -221.304358)
					(end 90.1954 -221.232222)
				)
			)
		)
	)
	(zone
		(layers "F.Cu" "B.Cu" "In1.Cu" "In2.Cu" "In3.Cu" "In4.Cu" "In5.Cu" "In6.Cu"
			"In7.Cu" "In8.Cu" "In9.Cu" "In10.Cu" "In11.Cu" "In12.Cu" "In13.Cu" "In14.Cu"
			"In15.Cu" "In16.Cu"
		)
		(hatch none 0.5)
		(connect_pads
			(clearance 0)
		)
		(min_thickness 0.25)
		(keepout
			(tracks not_allowed)
			(vias allowed)
			(pads allowed)
			(copperpour not_allowed)
			(footprints allowed)
		)
		(placement
			(enabled no)
			(sheetname "")
		)
		(fill
			(thermal_gap 0.5)
			(thermal_bridge_width 0.5)
			(island_removal_mode 0)
		)
		(polygon
			(pts
				(arc
					(start 367.427764 -224.389442)
					(mid 366.769904 -224.389442)
					(end 367.427764 -224.389442)
				)
			)
		)
	)
	(zone
		(layers "F.Cu" "B.Cu" "In1.Cu" "In2.Cu" "In3.Cu" "In4.Cu" "In5.Cu" "In6.Cu"
			"In7.Cu" "In8.Cu" "In9.Cu" "In10.Cu" "In11.Cu" "In12.Cu" "In13.Cu" "In14.Cu"
			"In15.Cu" "In16.Cu"
		)
		(hatch none 0.5)
		(connect_pads
			(clearance 0)
		)
		(min_thickness 0.25)
		(keepout
			(tracks not_allowed)
			(vias allowed)
			(pads allowed)
			(copperpour not_allowed)
			(footprints allowed)
		)
		(placement
			(enabled no)
			(sheetname "")
		)
		(fill
			(thermal_gap 0.5)
			(thermal_bridge_width 0.5)
			(island_removal_mode 0)
		)
		(polygon
			(pts
				(arc
					(start 344.236548 -213.646766)
					(mid 344.16884 -213.574915)
					(end 344.073734 -213.548468)
				)
				(arc
					(start 344.073734 -213.548468)
					(mid 343.94352 -213.602404)
					(end 343.889584 -213.732618)
				)
				(arc
					(start 343.889584 -213.732618)
					(mid 343.895035 -213.776839)
					(end 343.91092 -213.81847)
				)
				(arc
					(start 344.380312 -214.708486)
					(mid 344.44802 -214.780337)
					(end 344.543126 -214.806784)
				)
				(arc
					(start 344.543126 -214.806784)
					(mid 344.67334 -214.752848)
					(end 344.727276 -214.622634)
				)
				(arc
					(start 344.727276 -214.622634)
					(mid 344.721825 -214.578413)
					(end 344.70594 -214.536782)
				)
			)
		)
	)
	(zone
		(layers "F.Cu" "B.Cu" "In1.Cu" "In2.Cu" "In3.Cu" "In4.Cu" "In5.Cu" "In6.Cu"
			"In7.Cu" "In8.Cu" "In9.Cu" "In10.Cu" "In11.Cu" "In12.Cu" "In13.Cu" "In14.Cu"
			"In15.Cu" "In16.Cu"
		)
		(hatch none 0.5)
		(connect_pads
			(clearance 0)
		)
		(min_thickness 0.25)
		(keepout
			(tracks not_allowed)
			(vias allowed)
			(pads allowed)
			(copperpour not_allowed)
			(footprints allowed)
		)
		(placement
			(enabled no)
			(sheetname "")
		)
		(fill
			(thermal_gap 0.5)
			(thermal_bridge_width 0.5)
			(island_removal_mode 0)
		)
		(polygon
			(pts
				(arc
					(start 107.691682 -277.424134)
					(mid 107.619693 -277.351975)
					(end 107.521248 -277.325582)
				)
				(arc
					(start 107.521248 -277.325582)
					(mid 107.382054 -277.383238)
					(end 107.324398 -277.522432)
				)
				(arc
					(start 107.324398 -277.522432)
					(mid 107.331155 -277.573313)
					(end 107.350814 -277.62073)
				)
				(arc
					(start 107.820714 -278.4348)
					(mid 107.892703 -278.506959)
					(end 107.991148 -278.533352)
				)
				(arc
					(start 107.991148 -278.533352)
					(mid 108.130342 -278.475696)
					(end 108.187998 -278.336502)
				)
				(arc
					(start 108.187998 -278.336502)
					(mid 108.181241 -278.285621)
					(end 108.161582 -278.238204)
				)
			)
		)
	)
	(zone
		(layers "F.Cu" "B.Cu" "In1.Cu" "In2.Cu" "In3.Cu" "In4.Cu" "In5.Cu" "In6.Cu"
			"In7.Cu" "In8.Cu" "In9.Cu" "In10.Cu" "In11.Cu" "In12.Cu" "In13.Cu" "In14.Cu"
			"In15.Cu" "In16.Cu"
		)
		(hatch none 0.5)
		(connect_pads
			(clearance 0)
		)
		(min_thickness 0.25)
		(keepout
			(tracks not_allowed)
			(vias allowed)
			(pads allowed)
			(copperpour not_allowed)
			(footprints allowed)
		)
		(placement
			(enabled no)
			(sheetname "")
		)
		(fill
			(thermal_gap 0.5)
			(thermal_bridge_width 0.5)
			(island_removal_mode 0)
		)
		(polygon
			(pts
				(arc
					(start 26.709878 -17.23136)
					(mid 26.328878 -17.61236)
					(end 26.709878 -17.99336)
				)
				(arc
					(start 27.573478 -17.99336)
					(mid 27.954478 -17.61236)
					(end 27.573478 -17.23136)
				)
			)
		)
	)
	(zone
		(layers "F.Cu" "B.Cu" "In1.Cu" "In2.Cu" "In3.Cu" "In4.Cu" "In5.Cu" "In6.Cu"
			"In7.Cu" "In8.Cu" "In9.Cu" "In10.Cu" "In11.Cu" "In12.Cu" "In13.Cu" "In14.Cu"
			"In15.Cu" "In16.Cu"
		)
		(hatch none 0.5)
		(connect_pads
			(clearance 0)
		)
		(min_thickness 0.25)
		(keepout
			(tracks not_allowed)
			(vias allowed)
			(pads allowed)
			(copperpour not_allowed)
			(footprints allowed)
		)
		(placement
			(enabled no)
			(sheetname "")
		)
		(fill
			(thermal_gap 0.5)
			(thermal_bridge_width 0.5)
			(island_removal_mode 0)
		)
		(polygon
			(pts
				(arc
					(start 131.546092 -217.97645)
					(mid 131.565776 -217.92904)
					(end 131.572508 -217.878152)
				)
				(arc
					(start 131.572508 -217.878152)
					(mid 131.514852 -217.738958)
					(end 131.375658 -217.681302)
				)
				(arc
					(start 131.375658 -217.681302)
					(mid 131.277227 -217.707718)
					(end 131.205224 -217.779854)
				)
				(arc
					(start 130.735578 -218.593924)
					(mid 130.715894 -218.641334)
					(end 130.709162 -218.692222)
				)
				(arc
					(start 130.709162 -218.692222)
					(mid 130.766818 -218.831416)
					(end 130.906012 -218.889072)
				)
				(arc
					(start 130.906012 -218.889072)
					(mid 131.004443 -218.862656)
					(end 131.076446 -218.79052)
				)
			)
		)
	)
	(zone
		(layers "F.Cu" "B.Cu" "In1.Cu" "In2.Cu" "In3.Cu" "In4.Cu" "In5.Cu" "In6.Cu"
			"In7.Cu" "In8.Cu" "In9.Cu" "In10.Cu" "In11.Cu" "In12.Cu" "In13.Cu" "In14.Cu"
			"In15.Cu" "In16.Cu"
		)
		(hatch none 0.5)
		(connect_pads
			(clearance 0)
		)
		(min_thickness 0.25)
		(keepout
			(tracks not_allowed)
			(vias allowed)
			(pads allowed)
			(copperpour not_allowed)
			(footprints allowed)
		)
		(placement
			(enabled no)
			(sheetname "")
		)
		(fill
			(thermal_gap 0.5)
			(thermal_bridge_width 0.5)
			(island_removal_mode 0)
		)
		(polygon
			(pts
				(arc
					(start 124.186696 -217.878406)
					(mid 123.528836 -217.878406)
					(end 124.186696 -217.878406)
				)
			)
		)
	)
	(zone
		(layers "F.Cu" "B.Cu" "In1.Cu" "In2.Cu" "In3.Cu" "In4.Cu" "In5.Cu" "In6.Cu"
			"In7.Cu" "In8.Cu" "In9.Cu" "In10.Cu" "In11.Cu" "In12.Cu" "In13.Cu" "In14.Cu"
			"In15.Cu" "In16.Cu"
		)
		(hatch none 0.5)
		(connect_pads
			(clearance 0)
		)
		(min_thickness 0.25)
		(keepout
			(tracks not_allowed)
			(vias allowed)
			(pads allowed)
			(copperpour not_allowed)
			(footprints allowed)
		)
		(placement
			(enabled no)
			(sheetname "")
		)
		(fill
			(thermal_gap 0.5)
			(thermal_bridge_width 0.5)
			(island_removal_mode 0)
		)
		(polygon
			(pts
				(arc
					(start 343.572592 -282.405836)
					(mid 342.914732 -282.405836)
					(end 343.572592 -282.405836)
				)
			)
		)
	)
	(zone
		(layers "F.Cu" "B.Cu" "In1.Cu" "In2.Cu" "In3.Cu" "In4.Cu" "In5.Cu" "In6.Cu"
			"In7.Cu" "In8.Cu" "In9.Cu" "In10.Cu" "In11.Cu" "In12.Cu" "In13.Cu" "In14.Cu"
			"In15.Cu" "In16.Cu"
		)
		(hatch none 0.5)
		(connect_pads
			(clearance 0)
		)
		(min_thickness 0.25)
		(keepout
			(tracks not_allowed)
			(vias allowed)
			(pads allowed)
			(copperpour not_allowed)
			(footprints allowed)
		)
		(placement
			(enabled no)
			(sheetname "")
		)
		(fill
			(thermal_gap 0.5)
			(thermal_bridge_width 0.5)
			(island_removal_mode 0)
		)
		(polygon
			(pts
				(arc
					(start 108.601764 -276.708616)
					(mid 109.259624 -276.708616)
					(end 108.601764 -276.708616)
				)
			)
		)
	)
	(zone
		(layers "F.Cu" "B.Cu" "In1.Cu" "In2.Cu" "In3.Cu" "In4.Cu" "In5.Cu" "In6.Cu"
			"In7.Cu" "In8.Cu" "In9.Cu" "In10.Cu" "In11.Cu" "In12.Cu" "In13.Cu" "In14.Cu"
			"In15.Cu" "In16.Cu"
		)
		(hatch none 0.5)
		(connect_pads
			(clearance 0)
		)
		(min_thickness 0.25)
		(keepout
			(tracks not_allowed)
			(vias allowed)
			(pads allowed)
			(copperpour not_allowed)
			(footprints allowed)
		)
		(placement
			(enabled no)
			(sheetname "")
		)
		(fill
			(thermal_gap 0.5)
			(thermal_bridge_width 0.5)
			(island_removal_mode 0)
		)
		(polygon
			(pts
				(arc
					(start 95.052896 -217.878406)
					(mid 94.395036 -217.878406)
					(end 95.052896 -217.878406)
				)
			)
		)
	)
	(zone
		(layers "F.Cu" "B.Cu" "In1.Cu" "In2.Cu" "In3.Cu" "In4.Cu" "In5.Cu" "In6.Cu"
			"In7.Cu" "In8.Cu" "In9.Cu" "In10.Cu" "In11.Cu" "In12.Cu" "In13.Cu" "In14.Cu"
			"In15.Cu" "In16.Cu"
		)
		(hatch none 0.5)
		(connect_pads
			(clearance 0)
		)
		(min_thickness 0.25)
		(keepout
			(tracks not_allowed)
			(vias allowed)
			(pads allowed)
			(copperpour not_allowed)
			(footprints allowed)
		)
		(placement
			(enabled no)
			(sheetname "")
		)
		(fill
			(thermal_gap 0.5)
			(thermal_bridge_width 0.5)
			(island_removal_mode 0)
		)
		(polygon
			(pts
				(arc
					(start 340.254082 -288.818828)
					(mid 340.234398 -288.866238)
					(end 340.227666 -288.917126)
				)
				(arc
					(start 340.227666 -288.917126)
					(mid 340.285322 -289.05632)
					(end 340.424516 -289.113976)
				)
				(arc
					(start 340.424516 -289.113976)
					(mid 340.522947 -289.08756)
					(end 340.59495 -289.015424)
				)
				(arc
					(start 341.06485 -288.201354)
					(mid 341.084534 -288.153944)
					(end 341.091266 -288.103056)
				)
				(arc
					(start 341.091266 -288.103056)
					(mid 341.03361 -287.963862)
					(end 340.894416 -287.906206)
				)
				(arc
					(start 340.894416 -287.906206)
					(mid 340.795985 -287.932622)
					(end 340.723982 -288.004758)
				)
			)
		)
	)
	(zone
		(layers "F.Cu" "B.Cu" "In1.Cu" "In2.Cu" "In3.Cu" "In4.Cu" "In5.Cu" "In6.Cu"
			"In7.Cu" "In8.Cu" "In9.Cu" "In10.Cu" "In11.Cu" "In12.Cu" "In13.Cu" "In14.Cu"
			"In15.Cu" "In16.Cu"
		)
		(hatch none 0.5)
		(connect_pads
			(clearance 0)
		)
		(min_thickness 0.25)
		(keepout
			(tracks not_allowed)
			(vias allowed)
			(pads allowed)
			(copperpour not_allowed)
			(footprints allowed)
		)
		(placement
			(enabled no)
			(sheetname "")
		)
		(fill
			(thermal_gap 0.5)
			(thermal_bridge_width 0.5)
			(island_removal_mode 0)
		)
		(polygon
			(pts
				(arc
					(start 103.12146 -411.594808)
					(mid 103.50246 -411.213808)
					(end 103.12146 -410.832808)
				)
				(arc
					(start 102.25786 -410.832808)
					(mid 101.87686 -411.213808)
					(end 102.25786 -411.594808)
				)
			)
		)
	)
	(zone
		(layers "F.Cu" "B.Cu" "In1.Cu" "In2.Cu" "In3.Cu" "In4.Cu" "In5.Cu" "In6.Cu"
			"In7.Cu" "In8.Cu" "In9.Cu" "In10.Cu" "In11.Cu" "In12.Cu" "In13.Cu" "In14.Cu"
			"In15.Cu" "In16.Cu"
		)
		(hatch none 0.5)
		(connect_pads
			(clearance 0)
		)
		(min_thickness 0.25)
		(keepout
			(tracks not_allowed)
			(vias allowed)
			(pads allowed)
			(copperpour not_allowed)
			(footprints allowed)
		)
		(placement
			(enabled no)
			(sheetname "")
		)
		(fill
			(thermal_gap 0.5)
			(thermal_bridge_width 0.5)
			(island_removal_mode 0)
		)
		(polygon
			(pts
				(arc
					(start 90.353388 -214.622634)
					(mid 89.695528 -214.622634)
					(end 90.353388 -214.622634)
				)
			)
		)
	)
	(zone
		(layers "F.Cu" "B.Cu" "In1.Cu" "In2.Cu" "In3.Cu" "In4.Cu" "In5.Cu" "In6.Cu"
			"In7.Cu" "In8.Cu" "In9.Cu" "In10.Cu" "In11.Cu" "In12.Cu" "In13.Cu" "In14.Cu"
			"In15.Cu" "In16.Cu"
		)
		(hatch none 0.5)
		(connect_pads
			(clearance 0)
		)
		(min_thickness 0.25)
		(keepout
			(tracks not_allowed)
			(vias allowed)
			(pads allowed)
			(copperpour not_allowed)
			(footprints allowed)
		)
		(placement
			(enabled no)
			(sheetname "")
		)
		(fill
			(thermal_gap 0.5)
			(thermal_bridge_width 0.5)
			(island_removal_mode 0)
		)
		(polygon
			(pts
				(arc
					(start 336.88401 -215.436704)
					(mid 336.22615 -215.436704)
					(end 336.88401 -215.436704)
				)
			)
		)
	)
	(zone
		(layers "F.Cu" "B.Cu" "In1.Cu" "In2.Cu" "In3.Cu" "In4.Cu" "In5.Cu" "In6.Cu"
			"In7.Cu" "In8.Cu" "In9.Cu" "In10.Cu" "In11.Cu" "In12.Cu" "In13.Cu" "In14.Cu"
			"In15.Cu" "In16.Cu"
		)
		(hatch none 0.5)
		(connect_pads
			(clearance 0)
		)
		(min_thickness 0.25)
		(keepout
			(tracks not_allowed)
			(vias allowed)
			(pads allowed)
			(copperpour not_allowed)
			(footprints allowed)
		)
		(placement
			(enabled no)
			(sheetname "")
		)
		(fill
			(thermal_gap 0.5)
			(thermal_bridge_width 0.5)
			(island_removal_mode 0)
		)
		(polygon
			(pts
				(arc
					(start 125.988318 -288.917126)
					(mid 126.646178 -288.917126)
					(end 125.988318 -288.917126)
				)
			)
		)
	)
	(zone
		(layers "F.Cu" "B.Cu" "In1.Cu" "In2.Cu" "In3.Cu" "In4.Cu" "In5.Cu" "In6.Cu"
			"In7.Cu" "In8.Cu" "In9.Cu" "In10.Cu" "In11.Cu" "In12.Cu" "In13.Cu" "In14.Cu"
			"In15.Cu" "In16.Cu"
		)
		(hatch none 0.5)
		(connect_pads
			(clearance 0)
		)
		(min_thickness 0.25)
		(keepout
			(tracks not_allowed)
			(vias allowed)
			(pads allowed)
			(copperpour not_allowed)
			(footprints allowed)
		)
		(placement
			(enabled no)
			(sheetname "")
		)
		(fill
			(thermal_gap 0.5)
			(thermal_bridge_width 0.5)
			(island_removal_mode 0)
		)
		(polygon
			(pts
				(arc
					(start 348.657672 -173.661832)
					(mid 348.806462 -174.021042)
					(end 349.165672 -174.169832)
				)
				(arc
					(start 349.16618 -174.169832)
					(mid 349.297389 -174.152595)
					(end 349.419672 -174.102014)
				)
				(arc
					(start 350.343724 -173.56836)
					(mid 350.529657 -173.382424)
					(end 350.597724 -173.128432)
				)
				(arc
					(start 350.597724 -173.128432)
					(mid 350.448934 -172.769222)
					(end 350.089724 -172.620432)
				)
				(arc
					(start 350.089216 -172.620432)
					(mid 349.958007 -172.637669)
					(end 349.835724 -172.68825)
				)
				(arc
					(start 348.911672 -173.221904)
					(mid 348.725739 -173.40784)
					(end 348.657672 -173.661832)
				)
			)
		)
	)
	(zone
		(layers "F.Cu" "B.Cu" "In1.Cu" "In2.Cu" "In3.Cu" "In4.Cu" "In5.Cu" "In6.Cu"
			"In7.Cu" "In8.Cu" "In9.Cu" "In10.Cu" "In11.Cu" "In12.Cu" "In13.Cu" "In14.Cu"
			"In15.Cu" "In16.Cu"
		)
		(hatch none 0.5)
		(connect_pads
			(clearance 0)
		)
		(min_thickness 0.25)
		(keepout
			(tracks not_allowed)
			(vias allowed)
			(pads allowed)
			(copperpour not_allowed)
			(footprints allowed)
		)
		(placement
			(enabled no)
			(sheetname "")
		)
		(fill
			(thermal_gap 0.5)
			(thermal_bridge_width 0.5)
			(island_removal_mode 0)
		)
		(polygon
			(pts
				(arc
					(start 50.544984 -417.770056)
					(mid 45.036994 -412.262066)
					(end 39.529004 -417.770056)
				)
				(arc
					(start 39.529004 -424.470068)
					(mid 45.036994 -429.978058)
					(end 50.544984 -424.470068)
				)
			)
		)
	)
	(zone
		(layers "F.Cu" "B.Cu" "In1.Cu" "In2.Cu" "In3.Cu" "In4.Cu" "In5.Cu" "In6.Cu"
			"In7.Cu" "In8.Cu" "In9.Cu" "In10.Cu" "In11.Cu" "In12.Cu" "In13.Cu" "In14.Cu"
			"In15.Cu" "In16.Cu"
		)
		(hatch none 0.5)
		(connect_pads
			(clearance 0)
		)
		(min_thickness 0.25)
		(keepout
			(tracks not_allowed)
			(vias allowed)
			(pads allowed)
			(copperpour not_allowed)
			(footprints allowed)
		)
		(placement
			(enabled no)
			(sheetname "")
		)
		(fill
			(thermal_gap 0.5)
			(thermal_bridge_width 0.5)
			(island_removal_mode 0)
		)
		(polygon
			(pts
				(arc
					(start 87.926164 -283.219906)
					(mid 88.584024 -283.219906)
					(end 87.926164 -283.219906)
				)
			)
		)
	)
	(zone
		(layers "F.Cu" "B.Cu" "In1.Cu" "In2.Cu" "In3.Cu" "In4.Cu" "In5.Cu" "In6.Cu"
			"In7.Cu" "In8.Cu" "In9.Cu" "In10.Cu" "In11.Cu" "In12.Cu" "In13.Cu" "In14.Cu"
			"In15.Cu" "In16.Cu"
		)
		(hatch none 0.5)
		(connect_pads
			(clearance 0)
		)
		(min_thickness 0.25)
		(keepout
			(tracks not_allowed)
			(vias allowed)
			(pads allowed)
			(copperpour not_allowed)
			(footprints allowed)
		)
		(placement
			(enabled no)
			(sheetname "")
		)
		(fill
			(thermal_gap 0.5)
			(thermal_bridge_width 0.5)
			(island_removal_mode 0)
		)
		(polygon
			(pts
				(arc
					(start 130.295142 -217.064336)
					(mid 129.637282 -217.064336)
					(end 130.295142 -217.064336)
				)
			)
		)
	)
	(zone
		(layers "F.Cu" "B.Cu" "In1.Cu" "In2.Cu" "In3.Cu" "In4.Cu" "In5.Cu" "In6.Cu"
			"In7.Cu" "In8.Cu" "In9.Cu" "In10.Cu" "In11.Cu" "In12.Cu" "In13.Cu" "In14.Cu"
			"In15.Cu" "In16.Cu"
		)
		(hatch none 0.5)
		(connect_pads
			(clearance 0)
		)
		(min_thickness 0.25)
		(keepout
			(tracks not_allowed)
			(vias allowed)
			(pads allowed)
			(copperpour not_allowed)
			(footprints allowed)
		)
		(placement
			(enabled no)
			(sheetname "")
		)
		(fill
			(thermal_gap 0.5)
			(thermal_bridge_width 0.5)
			(island_removal_mode 0)
		)
		(polygon
			(pts
				(arc
					(start 340.84768 -136.759188)
					(mid 340.46668 -136.378188)
					(end 340.08568 -136.759188)
				)
				(arc
					(start 340.08568 -137.622788)
					(mid 340.46668 -138.003788)
					(end 340.84768 -137.622788)
				)
			)
		)
	)
	(zone
		(layers "F.Cu" "B.Cu" "In1.Cu" "In2.Cu" "In3.Cu" "In4.Cu" "In5.Cu" "In6.Cu"
			"In7.Cu" "In8.Cu" "In9.Cu" "In10.Cu" "In11.Cu" "In12.Cu" "In13.Cu" "In14.Cu"
			"In15.Cu" "In16.Cu"
		)
		(hatch none 0.5)
		(connect_pads
			(clearance 0)
		)
		(min_thickness 0.25)
		(keepout
			(tracks not_allowed)
			(vias allowed)
			(pads allowed)
			(copperpour not_allowed)
			(footprints allowed)
		)
		(placement
			(enabled no)
			(sheetname "")
		)
		(fill
			(thermal_gap 0.5)
			(thermal_bridge_width 0.5)
			(island_removal_mode 0)
		)
		(polygon
			(pts
				(arc
					(start 106.800142 -218.692222)
					(mid 106.142282 -218.692222)
					(end 106.800142 -218.692222)
				)
			)
		)
	)
	(zone
		(layers "F.Cu" "B.Cu" "In1.Cu" "In2.Cu" "In3.Cu" "In4.Cu" "In5.Cu" "In6.Cu"
			"In7.Cu" "In8.Cu" "In9.Cu" "In10.Cu" "In11.Cu" "In12.Cu" "In13.Cu" "In14.Cu"
			"In15.Cu" "In16.Cu"
		)
		(hatch none 0.5)
		(connect_pads
			(clearance 0)
		)
		(min_thickness 0.25)
		(keepout
			(tracks not_allowed)
			(vias allowed)
			(pads allowed)
			(copperpour not_allowed)
			(footprints allowed)
		)
		(placement
			(enabled no)
			(sheetname "")
		)
		(fill
			(thermal_gap 0.5)
			(thermal_bridge_width 0.5)
			(island_removal_mode 0)
		)
		(polygon
			(pts
				(arc
					(start 124.296678 -286.475424)
					(mid 123.638818 -286.475424)
					(end 124.296678 -286.475424)
				)
			)
		)
	)
	(zone
		(layers "F.Cu" "B.Cu" "In1.Cu" "In2.Cu" "In3.Cu" "In4.Cu" "In5.Cu" "In6.Cu"
			"In7.Cu" "In8.Cu" "In9.Cu" "In10.Cu" "In11.Cu" "In12.Cu" "In13.Cu" "In14.Cu"
			"In15.Cu" "In16.Cu"
		)
		(hatch none 0.5)
		(connect_pads
			(clearance 0)
		)
		(min_thickness 0.25)
		(keepout
			(tracks not_allowed)
			(vias allowed)
			(pads allowed)
			(copperpour not_allowed)
			(footprints allowed)
		)
		(placement
			(enabled no)
			(sheetname "")
		)
		(fill
			(thermal_gap 0.5)
			(thermal_bridge_width 0.5)
			(island_removal_mode 0)
		)
		(polygon
			(pts
				(arc
					(start 130.577082 -215.436704)
					(mid 131.234942 -215.436704)
					(end 130.577082 -215.436704)
				)
			)
		)
	)
	(zone
		(layers "F.Cu" "B.Cu" "In1.Cu" "In2.Cu" "In3.Cu" "In4.Cu" "In5.Cu" "In6.Cu"
			"In7.Cu" "In8.Cu" "In9.Cu" "In10.Cu" "In11.Cu" "In12.Cu" "In13.Cu" "In14.Cu"
			"In15.Cu" "In16.Cu"
		)
		(hatch none 0.5)
		(connect_pads
			(clearance 0)
		)
		(min_thickness 0.25)
		(keepout
			(tracks not_allowed)
			(vias allowed)
			(pads allowed)
			(copperpour not_allowed)
			(footprints allowed)
		)
		(placement
			(enabled no)
			(sheetname "")
		)
		(fill
			(thermal_gap 0.5)
			(thermal_bridge_width 0.5)
			(island_removal_mode 0)
		)
		(polygon
			(pts
				(arc
					(start 343.572592 -280.778204)
					(mid 342.914732 -280.778204)
					(end 343.572592 -280.778204)
				)
			)
		)
	)
	(zone
		(layers "F.Cu" "B.Cu" "In1.Cu" "In2.Cu" "In3.Cu" "In4.Cu" "In5.Cu" "In6.Cu"
			"In7.Cu" "In8.Cu" "In9.Cu" "In10.Cu" "In11.Cu" "In12.Cu" "In13.Cu" "In14.Cu"
			"In15.Cu" "In16.Cu"
		)
		(hatch none 0.5)
		(connect_pads
			(clearance 0)
		)
		(min_thickness 0.25)
		(keepout
			(tracks not_allowed)
			(vias allowed)
			(pads allowed)
			(copperpour not_allowed)
			(footprints allowed)
		)
		(placement
			(enabled no)
			(sheetname "")
		)
		(fill
			(thermal_gap 0.5)
			(thermal_bridge_width 0.5)
			(island_removal_mode 0)
		)
		(polygon
			(pts
				(arc
					(start 112.438942 -218.692222)
					(mid 111.781082 -218.692222)
					(end 112.438942 -218.692222)
				)
			)
		)
	)
	(zone
		(layers "F.Cu" "B.Cu" "In1.Cu" "In2.Cu" "In3.Cu" "In4.Cu" "In5.Cu" "In6.Cu"
			"In7.Cu" "In8.Cu" "In9.Cu" "In10.Cu" "In11.Cu" "In12.Cu" "In13.Cu" "In14.Cu"
			"In15.Cu" "In16.Cu"
		)
		(hatch none 0.5)
		(connect_pads
			(clearance 0)
		)
		(min_thickness 0.25)
		(keepout
			(tracks not_allowed)
			(vias allowed)
			(pads allowed)
			(copperpour not_allowed)
			(footprints allowed)
		)
		(placement
			(enabled no)
			(sheetname "")
		)
		(fill
			(thermal_gap 0.5)
			(thermal_bridge_width 0.5)
			(island_removal_mode 0)
		)
		(polygon
			(pts
				(arc
					(start 156.913834 -400.477228)
					(mid 156.532834 -400.858228)
					(end 156.913834 -401.239228)
				)
				(arc
					(start 157.777434 -401.239228)
					(mid 158.158434 -400.858228)
					(end 157.777434 -400.477228)
				)
			)
		)
	)
	(zone
		(layers "F.Cu" "B.Cu" "In1.Cu" "In2.Cu" "In3.Cu" "In4.Cu" "In5.Cu" "In6.Cu"
			"In7.Cu" "In8.Cu" "In9.Cu" "In10.Cu" "In11.Cu" "In12.Cu" "In13.Cu" "In14.Cu"
			"In15.Cu" "In16.Cu"
		)
		(hatch none 0.5)
		(connect_pads
			(clearance 0)
		)
		(min_thickness 0.25)
		(keepout
			(tracks not_allowed)
			(vias allowed)
			(pads allowed)
			(copperpour not_allowed)
			(footprints allowed)
		)
		(placement
			(enabled no)
			(sheetname "")
		)
		(fill
			(thermal_gap 0.5)
			(thermal_bridge_width 0.5)
			(island_removal_mode 0)
		)
		(polygon
			(pts
				(arc
					(start 123.198636 -288.005012)
					(mid 123.126647 -287.932853)
					(end 123.028202 -287.90646)
				)
				(arc
					(start 123.028202 -287.90646)
					(mid 122.889008 -287.964116)
					(end 122.831352 -288.10331)
				)
				(arc
					(start 122.831352 -288.10331)
					(mid 122.838109 -288.154191)
					(end 122.857768 -288.201608)
				)
				(arc
					(start 123.327414 -289.015424)
					(mid 123.399403 -289.087583)
					(end 123.497848 -289.113976)
				)
				(arc
					(start 123.497848 -289.113976)
					(mid 123.637042 -289.05632)
					(end 123.694698 -288.917126)
				)
				(arc
					(start 123.694698 -288.917126)
					(mid 123.687941 -288.866245)
					(end 123.668282 -288.818828)
				)
			)
		)
	)
	(zone
		(layers "F.Cu" "B.Cu" "In1.Cu" "In2.Cu" "In3.Cu" "In4.Cu" "In5.Cu" "In6.Cu"
			"In7.Cu" "In8.Cu" "In9.Cu" "In10.Cu" "In11.Cu" "In12.Cu" "In13.Cu" "In14.Cu"
			"In15.Cu" "In16.Cu"
		)
		(hatch none 0.5)
		(connect_pads
			(clearance 0)
		)
		(min_thickness 0.25)
		(keepout
			(tracks not_allowed)
			(vias allowed)
			(pads allowed)
			(copperpour not_allowed)
			(footprints allowed)
		)
		(placement
			(enabled no)
			(sheetname "")
		)
		(fill
			(thermal_gap 0.5)
			(thermal_bridge_width 0.5)
			(island_removal_mode 0)
		)
		(polygon
			(pts
				(arc
					(start 106.330496 -221.133924)
					(mid 105.672636 -221.133924)
					(end 106.330496 -221.133924)
				)
			)
		)
	)
	(zone
		(layers "F.Cu" "B.Cu" "In1.Cu" "In2.Cu" "In3.Cu" "In4.Cu" "In5.Cu" "In6.Cu"
			"In7.Cu" "In8.Cu" "In9.Cu" "In10.Cu" "In11.Cu" "In12.Cu" "In13.Cu" "In14.Cu"
			"In15.Cu" "In16.Cu"
		)
		(hatch none 0.5)
		(connect_pads
			(clearance 0)
		)
		(min_thickness 0.25)
		(keepout
			(tracks not_allowed)
			(vias allowed)
			(pads allowed)
			(copperpour not_allowed)
			(footprints allowed)
		)
		(placement
			(enabled no)
			(sheetname "")
		)
		(fill
			(thermal_gap 0.5)
			(thermal_bridge_width 0.5)
			(island_removal_mode 0)
		)
		(polygon
			(pts
				(arc
					(start 90.165682 -220.319854)
					(mid 90.823542 -220.319854)
					(end 90.165682 -220.319854)
				)
			)
		)
	)
	(zone
		(layers "F.Cu" "B.Cu" "In1.Cu" "In2.Cu" "In3.Cu" "In4.Cu" "In5.Cu" "In6.Cu"
			"In7.Cu" "In8.Cu" "In9.Cu" "In10.Cu" "In11.Cu" "In12.Cu" "In13.Cu" "In14.Cu"
			"In15.Cu" "In16.Cu"
		)
		(hatch none 0.5)
		(connect_pads
			(clearance 0)
		)
		(min_thickness 0.25)
		(keepout
			(tracks not_allowed)
			(vias allowed)
			(pads allowed)
			(copperpour not_allowed)
			(footprints allowed)
		)
		(placement
			(enabled no)
			(sheetname "")
		)
		(fill
			(thermal_gap 0.5)
			(thermal_bridge_width 0.5)
			(island_removal_mode 0)
		)
		(polygon
			(pts
				(arc
					(start 121.179082 -215.436704)
					(mid 121.836942 -215.436704)
					(end 121.179082 -215.436704)
				)
			)
		)
	)
	(zone
		(layers "F.Cu" "B.Cu" "In1.Cu" "In2.Cu" "In3.Cu" "In4.Cu" "In5.Cu" "In6.Cu"
			"In7.Cu" "In8.Cu" "In9.Cu" "In10.Cu" "In11.Cu" "In12.Cu" "In13.Cu" "In14.Cu"
			"In15.Cu" "In16.Cu"
		)
		(hatch none 0.5)
		(connect_pads
			(clearance 0)
		)
		(min_thickness 0.25)
		(keepout
			(tracks not_allowed)
			(vias allowed)
			(pads allowed)
			(copperpour not_allowed)
			(footprints allowed)
		)
		(placement
			(enabled no)
			(sheetname "")
		)
		(fill
			(thermal_gap 0.5)
			(thermal_bridge_width 0.5)
			(island_removal_mode 0)
		)
		(polygon
			(pts
				(arc
					(start 447.402966 -153.774902)
					(mid 436.386986 -153.774902)
					(end 447.402966 -153.774902)
				)
			)
		)
	)
	(zone
		(layers "F.Cu" "B.Cu" "In1.Cu" "In2.Cu" "In3.Cu" "In4.Cu" "In5.Cu" "In6.Cu"
			"In7.Cu" "In8.Cu" "In9.Cu" "In10.Cu" "In11.Cu" "In12.Cu" "In13.Cu" "In14.Cu"
			"In15.Cu" "In16.Cu"
		)
		(hatch none 0.5)
		(connect_pads
			(clearance 0)
		)
		(min_thickness 0.25)
		(keepout
			(tracks not_allowed)
			(vias allowed)
			(pads allowed)
			(copperpour not_allowed)
			(footprints allowed)
		)
		(placement
			(enabled no)
			(sheetname "")
		)
		(fill
			(thermal_gap 0.5)
			(thermal_bridge_width 0.5)
			(island_removal_mode 0)
		)
		(polygon
			(pts
				(arc
					(start 373.75084 -161.265108)
					(mid 374.13184 -160.884108)
					(end 373.75084 -160.503108)
				)
				(arc
					(start 372.88724 -160.503108)
					(mid 372.50624 -160.884108)
					(end 372.88724 -161.265108)
				)
			)
		)
	)
	(zone
		(layers "F.Cu" "B.Cu" "In1.Cu" "In2.Cu" "In3.Cu" "In4.Cu" "In5.Cu" "In6.Cu"
			"In7.Cu" "In8.Cu" "In9.Cu" "In10.Cu" "In11.Cu" "In12.Cu" "In13.Cu" "In14.Cu"
			"In15.Cu" "In16.Cu"
		)
		(hatch none 0.5)
		(connect_pads
			(clearance 0)
		)
		(min_thickness 0.25)
		(keepout
			(tracks not_allowed)
			(vias allowed)
			(pads allowed)
			(copperpour not_allowed)
			(footprints allowed)
		)
		(placement
			(enabled no)
			(sheetname "")
		)
		(fill
			(thermal_gap 0.5)
			(thermal_bridge_width 0.5)
			(island_removal_mode 0)
		)
		(polygon
			(pts
				(arc
					(start 375.056146 -284.847538)
					(mid 374.398286 -284.847538)
					(end 375.056146 -284.847538)
				)
			)
		)
	)
	(zone
		(layers "F.Cu" "B.Cu" "In1.Cu" "In2.Cu" "In3.Cu" "In4.Cu" "In5.Cu" "In6.Cu"
			"In7.Cu" "In8.Cu" "In9.Cu" "In10.Cu" "In11.Cu" "In12.Cu" "In13.Cu" "In14.Cu"
			"In15.Cu" "In16.Cu"
		)
		(hatch none 0.5)
		(connect_pads
			(clearance 0)
		)
		(min_thickness 0.25)
		(keepout
			(tracks not_allowed)
			(vias allowed)
			(pads allowed)
			(copperpour not_allowed)
			(footprints allowed)
		)
		(placement
			(enabled no)
			(sheetname "")
		)
		(fill
			(thermal_gap 0.5)
			(thermal_bridge_width 0.5)
			(island_removal_mode 0)
		)
		(polygon
			(pts
				(arc
					(start 380.53645 -284.74924)
					(mid 380.464461 -284.677081)
					(end 380.366016 -284.650688)
				)
				(arc
					(start 380.366016 -284.650688)
					(mid 380.226822 -284.708344)
					(end 380.169166 -284.847538)
				)
				(arc
					(start 380.169166 -284.847538)
					(mid 380.175923 -284.898419)
					(end 380.195582 -284.945836)
				)
				(arc
					(start 380.665228 -285.759652)
					(mid 380.737217 -285.831811)
					(end 380.835662 -285.858204)
				)
				(arc
					(start 380.835662 -285.858204)
					(mid 380.974856 -285.800548)
					(end 381.032512 -285.661354)
				)
				(arc
					(start 381.032512 -285.661354)
					(mid 381.025755 -285.610473)
					(end 381.006096 -285.563056)
				)
			)
		)
	)
	(zone
		(layers "F.Cu" "B.Cu" "In1.Cu" "In2.Cu" "In3.Cu" "In4.Cu" "In5.Cu" "In6.Cu"
			"In7.Cu" "In8.Cu" "In9.Cu" "In10.Cu" "In11.Cu" "In12.Cu" "In13.Cu" "In14.Cu"
			"In15.Cu" "In16.Cu"
		)
		(hatch none 0.5)
		(connect_pads
			(clearance 0)
		)
		(min_thickness 0.25)
		(keepout
			(tracks not_allowed)
			(vias allowed)
			(pads allowed)
			(copperpour not_allowed)
			(footprints allowed)
		)
		(placement
			(enabled no)
			(sheetname "")
		)
		(fill
			(thermal_gap 0.5)
			(thermal_bridge_width 0.5)
			(island_removal_mode 0)
		)
		(polygon
			(pts
				(arc
					(start 341.692992 -285.661354)
					(mid 341.035132 -285.661354)
					(end 341.692992 -285.661354)
				)
			)
		)
	)
	(zone
		(layers "F.Cu" "B.Cu" "In1.Cu" "In2.Cu" "In3.Cu" "In4.Cu" "In5.Cu" "In6.Cu"
			"In7.Cu" "In8.Cu" "In9.Cu" "In10.Cu" "In11.Cu" "In12.Cu" "In13.Cu" "In14.Cu"
			"In15.Cu" "In16.Cu"
		)
		(hatch none 0.5)
		(connect_pads
			(clearance 0)
		)
		(min_thickness 0.25)
		(keepout
			(tracks not_allowed)
			(vias allowed)
			(pads allowed)
			(copperpour not_allowed)
			(footprints allowed)
		)
		(placement
			(enabled no)
			(sheetname "")
		)
		(fill
			(thermal_gap 0.5)
			(thermal_bridge_width 0.5)
			(island_removal_mode 0)
		)
		(polygon
			(pts
				(arc
					(start 99.751388 -214.622634)
					(mid 99.093528 -214.622634)
					(end 99.751388 -214.622634)
				)
			)
		)
	)
	(zone
		(layers "F.Cu" "B.Cu" "In1.Cu" "In2.Cu" "In3.Cu" "In4.Cu" "In5.Cu" "In6.Cu"
			"In7.Cu" "In8.Cu" "In9.Cu" "In10.Cu" "In11.Cu" "In12.Cu" "In13.Cu" "In14.Cu"
			"In15.Cu" "In16.Cu"
		)
		(hatch none 0.5)
		(connect_pads
			(clearance 0)
		)
		(min_thickness 0.25)
		(keepout
			(tracks not_allowed)
			(vias allowed)
			(pads allowed)
			(copperpour not_allowed)
			(footprints allowed)
		)
		(placement
			(enabled no)
			(sheetname "")
		)
		(fill
			(thermal_gap 0.5)
			(thermal_bridge_width 0.5)
			(island_removal_mode 0)
		)
		(polygon
			(pts
				(arc
					(start 372.438422 -220.22181)
					(mid 372.366433 -220.149651)
					(end 372.267988 -220.123258)
				)
				(arc
					(start 372.267988 -220.123258)
					(mid 372.128794 -220.180914)
					(end 372.071138 -220.320108)
				)
				(arc
					(start 372.071138 -220.320108)
					(mid 372.077895 -220.370989)
					(end 372.097554 -220.418406)
				)
				(arc
					(start 372.5672 -221.232222)
					(mid 372.639189 -221.304381)
					(end 372.737634 -221.330774)
				)
				(arc
					(start 372.737634 -221.330774)
					(mid 372.876828 -221.273118)
					(end 372.934484 -221.133924)
				)
				(arc
					(start 372.934484 -221.133924)
					(mid 372.927727 -221.083043)
					(end 372.908068 -221.035626)
				)
			)
		)
	)
	(zone
		(layers "F.Cu" "B.Cu" "In1.Cu" "In2.Cu" "In3.Cu" "In4.Cu" "In5.Cu" "In6.Cu"
			"In7.Cu" "In8.Cu" "In9.Cu" "In10.Cu" "In11.Cu" "In12.Cu" "In13.Cu" "In14.Cu"
			"In15.Cu" "In16.Cu"
		)
		(hatch none 0.5)
		(connect_pads
			(clearance 0)
		)
		(min_thickness 0.25)
		(keepout
			(tracks not_allowed)
			(vias allowed)
			(pads allowed)
			(copperpour not_allowed)
			(footprints allowed)
		)
		(placement
			(enabled no)
			(sheetname "")
		)
		(fill
			(thermal_gap 0.5)
			(thermal_bridge_width 0.5)
			(island_removal_mode 0)
		)
		(polygon
			(pts
				(arc
					(start 107.48772 -407.492708)
					(mid 107.86872 -407.111708)
					(end 107.48772 -406.730708)
				)
				(arc
					(start 106.62412 -406.730708)
					(mid 106.24312 -407.111708)
					(end 106.62412 -407.492708)
				)
			)
		)
	)
	(zone
		(layers "F.Cu" "B.Cu" "In1.Cu" "In2.Cu" "In3.Cu" "In4.Cu" "In5.Cu" "In6.Cu"
			"In7.Cu" "In8.Cu" "In9.Cu" "In10.Cu" "In11.Cu" "In12.Cu" "In13.Cu" "In14.Cu"
			"In15.Cu" "In16.Cu"
		)
		(hatch none 0.5)
		(connect_pads
			(clearance 0)
		)
		(min_thickness 0.25)
		(keepout
			(tracks not_allowed)
			(vias allowed)
			(pads allowed)
			(copperpour not_allowed)
			(footprints allowed)
		)
		(placement
			(enabled no)
			(sheetname "")
		)
		(fill
			(thermal_gap 0.5)
			(thermal_bridge_width 0.5)
			(island_removal_mode 0)
		)
		(polygon
			(pts
				(arc
					(start 418.71773 -409.649168)
					(mid 418.33673 -410.030168)
					(end 418.71773 -410.411168)
				)
				(arc
					(start 419.58133 -410.411168)
					(mid 419.96233 -410.030168)
					(end 419.58133 -409.649168)
				)
			)
		)
	)
	(zone
		(layers "F.Cu" "B.Cu" "In1.Cu" "In2.Cu" "In3.Cu" "In4.Cu" "In5.Cu" "In6.Cu"
			"In7.Cu" "In8.Cu" "In9.Cu" "In10.Cu" "In11.Cu" "In12.Cu" "In13.Cu" "In14.Cu"
			"In15.Cu" "In16.Cu"
		)
		(hatch none 0.5)
		(connect_pads
			(clearance 0)
		)
		(min_thickness 0.25)
		(keepout
			(tracks not_allowed)
			(vias allowed)
			(pads allowed)
			(copperpour not_allowed)
			(footprints allowed)
		)
		(placement
			(enabled no)
			(sheetname "")
		)
		(fill
			(thermal_gap 0.5)
			(thermal_bridge_width 0.5)
			(island_removal_mode 0)
		)
		(polygon
			(pts
				(arc
					(start 117.137942 -223.575626)
					(mid 116.480082 -223.575626)
					(end 117.137942 -223.575626)
				)
			)
		)
	)
	(zone
		(layers "F.Cu" "B.Cu" "In1.Cu" "In2.Cu" "In3.Cu" "In4.Cu" "In5.Cu" "In6.Cu"
			"In7.Cu" "In8.Cu" "In9.Cu" "In10.Cu" "In11.Cu" "In12.Cu" "In13.Cu" "In14.Cu"
			"In15.Cu" "In16.Cu"
		)
		(hatch none 0.5)
		(connect_pads
			(clearance 0)
		)
		(min_thickness 0.25)
		(keepout
			(tracks not_allowed)
			(vias allowed)
			(pads allowed)
			(copperpour not_allowed)
			(footprints allowed)
		)
		(placement
			(enabled no)
			(sheetname "")
		)
		(fill
			(thermal_gap 0.5)
			(thermal_bridge_width 0.5)
			(island_removal_mode 0)
		)
		(polygon
			(pts
				(arc
					(start 128.367028 -285.759652)
					(mid 128.386712 -285.712242)
					(end 128.393444 -285.661354)
				)
				(arc
					(start 128.393444 -285.661354)
					(mid 128.335788 -285.52216)
					(end 128.196594 -285.464504)
				)
				(arc
					(start 128.196594 -285.464504)
					(mid 128.098163 -285.49092)
					(end 128.02616 -285.563056)
				)
				(arc
					(start 127.556514 -286.377126)
					(mid 127.53683 -286.424536)
					(end 127.530098 -286.475424)
				)
				(arc
					(start 127.530098 -286.475424)
					(mid 127.587754 -286.614618)
					(end 127.726948 -286.672274)
				)
				(arc
					(start 127.726948 -286.672274)
					(mid 127.825379 -286.645858)
					(end 127.897382 -286.573722)
				)
			)
		)
	)
	(zone
		(layers "F.Cu" "B.Cu" "In1.Cu" "In2.Cu" "In3.Cu" "In4.Cu" "In5.Cu" "In6.Cu"
			"In7.Cu" "In8.Cu" "In9.Cu" "In10.Cu" "In11.Cu" "In12.Cu" "In13.Cu" "In14.Cu"
			"In15.Cu" "In16.Cu"
		)
		(hatch none 0.5)
		(connect_pads
			(clearance 0)
		)
		(min_thickness 0.25)
		(keepout
			(tracks not_allowed)
			(vias allowed)
			(pads allowed)
			(copperpour not_allowed)
			(footprints allowed)
		)
		(placement
			(enabled no)
			(sheetname "")
		)
		(fill
			(thermal_gap 0.5)
			(thermal_bridge_width 0.5)
			(island_removal_mode 0)
		)
		(polygon
			(pts
				(arc
					(start 339.12683 -84.865464)
					(mid 339.50783 -84.484464)
					(end 339.12683 -84.103464)
				)
				(arc
					(start 338.26323 -84.103464)
					(mid 337.88223 -84.484464)
					(end 338.26323 -84.865464)
				)
			)
		)
	)
	(zone
		(layers "F.Cu" "B.Cu" "In1.Cu" "In2.Cu" "In3.Cu" "In4.Cu" "In5.Cu" "In6.Cu"
			"In7.Cu" "In8.Cu" "In9.Cu" "In10.Cu" "In11.Cu" "In12.Cu" "In13.Cu" "In14.Cu"
			"In15.Cu" "In16.Cu"
		)
		(hatch none 0.5)
		(connect_pads
			(clearance 0)
		)
		(min_thickness 0.25)
		(keepout
			(tracks not_allowed)
			(vias allowed)
			(pads allowed)
			(copperpour not_allowed)
			(footprints allowed)
		)
		(placement
			(enabled no)
			(sheetname "")
		)
		(fill
			(thermal_gap 0.5)
			(thermal_bridge_width 0.5)
			(island_removal_mode 0)
		)
		(polygon
			(pts
				(arc
					(start 99.563682 -220.319854)
					(mid 100.221542 -220.319854)
					(end 99.563682 -220.319854)
				)
			)
		)
	)
	(zone
		(layers "F.Cu" "B.Cu" "In1.Cu" "In2.Cu" "In3.Cu" "In4.Cu" "In5.Cu" "In6.Cu"
			"In7.Cu" "In8.Cu" "In9.Cu" "In10.Cu" "In11.Cu" "In12.Cu" "In13.Cu" "In14.Cu"
			"In15.Cu" "In16.Cu"
		)
		(hatch none 0.5)
		(connect_pads
			(clearance 0)
		)
		(min_thickness 0.25)
		(keepout
			(tracks not_allowed)
			(vias allowed)
			(pads allowed)
			(copperpour not_allowed)
			(footprints allowed)
		)
		(placement
			(enabled no)
			(sheetname "")
		)
		(fill
			(thermal_gap 0.5)
			(thermal_bridge_width 0.5)
			(island_removal_mode 0)
		)
		(polygon
			(pts
				(arc
					(start 328.803 -76.502768)
					(mid 329.184 -76.121768)
					(end 328.803 -75.740768)
				)
				(arc
					(start 327.9394 -75.740768)
					(mid 327.5584 -76.121768)
					(end 327.9394 -76.502768)
				)
			)
		)
	)
	(zone
		(layers "F.Cu" "B.Cu" "In1.Cu" "In2.Cu" "In3.Cu" "In4.Cu" "In5.Cu" "In6.Cu"
			"In7.Cu" "In8.Cu" "In9.Cu" "In10.Cu" "In11.Cu" "In12.Cu" "In13.Cu" "In14.Cu"
			"In15.Cu" "In16.Cu"
		)
		(hatch none 0.5)
		(connect_pads
			(clearance 0)
		)
		(min_thickness 0.25)
		(keepout
			(tracks not_allowed)
			(vias allowed)
			(pads allowed)
			(copperpour not_allowed)
			(footprints allowed)
		)
		(placement
			(enabled no)
			(sheetname "")
		)
		(fill
			(thermal_gap 0.5)
			(thermal_bridge_width 0.5)
			(island_removal_mode 0)
		)
		(polygon
			(pts
				(arc
					(start 343.572592 -285.661354)
					(mid 342.914732 -285.661354)
					(end 343.572592 -285.661354)
				)
			)
		)
	)
	(zone
		(layers "F.Cu" "B.Cu" "In1.Cu" "In2.Cu" "In3.Cu" "In4.Cu" "In5.Cu" "In6.Cu"
			"In7.Cu" "In8.Cu" "In9.Cu" "In10.Cu" "In11.Cu" "In12.Cu" "In13.Cu" "In14.Cu"
			"In15.Cu" "In16.Cu"
		)
		(hatch none 0.5)
		(connect_pads
			(clearance 0)
		)
		(min_thickness 0.25)
		(keepout
			(tracks not_allowed)
			(vias allowed)
			(pads allowed)
			(copperpour not_allowed)
			(footprints allowed)
		)
		(placement
			(enabled no)
			(sheetname "")
		)
		(fill
			(thermal_gap 0.5)
			(thermal_bridge_width 0.5)
			(island_removal_mode 0)
		)
		(polygon
			(pts
				(arc
					(start 348.211648 -409.649168)
					(mid 347.830648 -410.030168)
					(end 348.211648 -410.411168)
				)
				(arc
					(start 349.075248 -410.411168)
					(mid 349.456248 -410.030168)
					(end 349.075248 -409.649168)
				)
			)
		)
	)
	(zone
		(layers "F.Cu" "B.Cu" "In1.Cu" "In2.Cu" "In3.Cu" "In4.Cu" "In5.Cu" "In6.Cu"
			"In7.Cu" "In8.Cu" "In9.Cu" "In10.Cu" "In11.Cu" "In12.Cu" "In13.Cu" "In14.Cu"
			"In15.Cu" "In16.Cu"
		)
		(hatch none 0.5)
		(connect_pads
			(clearance 0)
		)
		(min_thickness 0.25)
		(keepout
			(tracks not_allowed)
			(vias allowed)
			(pads allowed)
			(copperpour not_allowed)
			(footprints allowed)
		)
		(placement
			(enabled no)
			(sheetname "")
		)
		(fill
			(thermal_gap 0.5)
			(thermal_bridge_width 0.5)
			(island_removal_mode 0)
		)
		(polygon
			(pts
				(arc
					(start 413.434276 -6.332474)
					(mid 413.053276 -6.713474)
					(end 413.434276 -7.094474)
				)
				(arc
					(start 414.297876 -7.094474)
					(mid 414.678876 -6.713474)
					(end 414.297876 -6.332474)
				)
			)
		)
	)
	(zone
		(layers "F.Cu" "B.Cu" "In1.Cu" "In2.Cu" "In3.Cu" "In4.Cu" "In5.Cu" "In6.Cu"
			"In7.Cu" "In8.Cu" "In9.Cu" "In10.Cu" "In11.Cu" "In12.Cu" "In13.Cu" "In14.Cu"
			"In15.Cu" "In16.Cu"
		)
		(hatch none 0.5)
		(connect_pads
			(clearance 0)
		)
		(min_thickness 0.25)
		(keepout
			(tracks not_allowed)
			(vias allowed)
			(pads allowed)
			(copperpour not_allowed)
			(footprints allowed)
		)
		(placement
			(enabled no)
			(sheetname "")
		)
		(fill
			(thermal_gap 0.5)
			(thermal_bridge_width 0.5)
			(island_removal_mode 0)
		)
		(polygon
			(pts
				(arc
					(start 349.928688 -403.502876)
					(mid 349.547688 -403.883876)
					(end 349.928688 -404.264876)
				)
				(arc
					(start 350.792288 -404.264876)
					(mid 351.173288 -403.883876)
					(end 350.792288 -403.502876)
				)
			)
		)
	)
	(zone
		(layers "F.Cu" "B.Cu" "In1.Cu" "In2.Cu" "In3.Cu" "In4.Cu" "In5.Cu" "In6.Cu"
			"In7.Cu" "In8.Cu" "In9.Cu" "In10.Cu" "In11.Cu" "In12.Cu" "In13.Cu" "In14.Cu"
			"In15.Cu" "In16.Cu"
		)
		(hatch none 0.5)
		(connect_pads
			(clearance 0)
		)
		(min_thickness 0.25)
		(keepout
			(tracks not_allowed)
			(vias allowed)
			(pads allowed)
			(copperpour not_allowed)
			(footprints allowed)
		)
		(placement
			(enabled no)
			(sheetname "")
		)
		(fill
			(thermal_gap 0.5)
			(thermal_bridge_width 0.5)
			(island_removal_mode 0)
		)
		(polygon
			(pts
				(arc
					(start 349.352616 -283.023056)
					(mid 349.155766 -283.219906)
					(end 349.352616 -283.416756)
				)
				(arc
					(start 350.292416 -283.416756)
					(mid 350.489266 -283.219906)
					(end 350.292416 -283.023056)
				)
			)
		)
	)
	(zone
		(layers "F.Cu" "B.Cu" "In1.Cu" "In2.Cu" "In3.Cu" "In4.Cu" "In5.Cu" "In6.Cu"
			"In7.Cu" "In8.Cu" "In9.Cu" "In10.Cu" "In11.Cu" "In12.Cu" "In13.Cu" "In14.Cu"
			"In15.Cu" "In16.Cu"
		)
		(hatch none 0.5)
		(connect_pads
			(clearance 0)
		)
		(min_thickness 0.25)
		(keepout
			(tracks not_allowed)
			(vias allowed)
			(pads allowed)
			(copperpour not_allowed)
			(footprints allowed)
		)
		(placement
			(enabled no)
			(sheetname "")
		)
		(fill
			(thermal_gap 0.5)
			(thermal_bridge_width 0.5)
			(island_removal_mode 0)
		)
		(polygon
			(pts
				(arc
					(start 379.645164 -221.133924)
					(mid 378.987304 -221.133924)
					(end 379.645164 -221.133924)
				)
			)
		)
	)
	(zone
		(layers "F.Cu" "B.Cu" "In1.Cu" "In2.Cu" "In3.Cu" "In4.Cu" "In5.Cu" "In6.Cu"
			"In7.Cu" "In8.Cu" "In9.Cu" "In10.Cu" "In11.Cu" "In12.Cu" "In13.Cu" "In14.Cu"
			"In15.Cu" "In16.Cu"
		)
		(hatch none 0.5)
		(connect_pads
			(clearance 0)
		)
		(min_thickness 0.25)
		(keepout
			(tracks not_allowed)
			(vias allowed)
			(pads allowed)
			(copperpour not_allowed)
			(footprints allowed)
		)
		(placement
			(enabled no)
			(sheetname "")
		)
		(fill
			(thermal_gap 0.5)
			(thermal_bridge_width 0.5)
			(island_removal_mode 0)
		)
		(polygon
			(pts
				(arc
					(start 212.979254 -5.1308)
					(mid 213.360254 -5.5118)
					(end 213.741254 -5.1308)
				)
				(arc
					(start 213.741254 -4.2672)
					(mid 213.360254 -3.8862)
					(end 212.979254 -4.2672)
				)
			)
		)
	)
	(zone
		(layers "F.Cu" "B.Cu" "In1.Cu" "In2.Cu" "In3.Cu" "In4.Cu" "In5.Cu" "In6.Cu"
			"In7.Cu" "In8.Cu" "In9.Cu" "In10.Cu" "In11.Cu" "In12.Cu" "In13.Cu" "In14.Cu"
			"In15.Cu" "In16.Cu"
		)
		(hatch none 0.5)
		(connect_pads
			(clearance 0)
		)
		(min_thickness 0.25)
		(keepout
			(tracks not_allowed)
			(vias allowed)
			(pads allowed)
			(copperpour not_allowed)
			(footprints allowed)
		)
		(placement
			(enabled no)
			(sheetname "")
		)
		(fill
			(thermal_gap 0.5)
			(thermal_bridge_width 0.5)
			(island_removal_mode 0)
		)
		(polygon
			(pts
				(arc
					(start 358.029764 -221.133924)
					(mid 357.371904 -221.133924)
					(end 358.029764 -221.133924)
				)
			)
		)
	)
	(zone
		(layers "F.Cu" "B.Cu" "In1.Cu" "In2.Cu" "In3.Cu" "In4.Cu" "In5.Cu" "In6.Cu"
			"In7.Cu" "In8.Cu" "In9.Cu" "In10.Cu" "In11.Cu" "In12.Cu" "In13.Cu" "In14.Cu"
			"In15.Cu" "In16.Cu"
		)
		(hatch none 0.5)
		(connect_pads
			(clearance 0)
		)
		(min_thickness 0.25)
		(keepout
			(tracks not_allowed)
			(vias allowed)
			(pads allowed)
			(copperpour not_allowed)
			(footprints allowed)
		)
		(placement
			(enabled no)
			(sheetname "")
		)
		(fill
			(thermal_gap 0.5)
			(thermal_bridge_width 0.5)
			(island_removal_mode 0)
		)
		(polygon
			(pts
				(arc
					(start 388.08533 -409.649168)
					(mid 387.70433 -410.030168)
					(end 388.08533 -410.411168)
				)
				(arc
					(start 388.94893 -410.411168)
					(mid 389.32993 -410.030168)
					(end 388.94893 -409.649168)
				)
			)
		)
	)
	(zone
		(layers "F.Cu" "B.Cu" "In1.Cu" "In2.Cu" "In3.Cu" "In4.Cu" "In5.Cu" "In6.Cu"
			"In7.Cu" "In8.Cu" "In9.Cu" "In10.Cu" "In11.Cu" "In12.Cu" "In13.Cu" "In14.Cu"
			"In15.Cu" "In16.Cu"
		)
		(hatch none 0.5)
		(connect_pads
			(clearance 0)
		)
		(min_thickness 0.25)
		(keepout
			(tracks not_allowed)
			(vias allowed)
			(pads allowed)
			(copperpour not_allowed)
			(footprints allowed)
		)
		(placement
			(enabled no)
			(sheetname "")
		)
		(fill
			(thermal_gap 0.5)
			(thermal_bridge_width 0.5)
			(island_removal_mode 0)
		)
		(polygon
			(pts
				(arc
					(start 130.764788 -214.622634)
					(mid 130.106928 -214.622634)
					(end 130.764788 -214.622634)
				)
			)
		)
	)
	(zone
		(layers "F.Cu" "B.Cu" "In1.Cu" "In2.Cu" "In3.Cu" "In4.Cu" "In5.Cu" "In6.Cu"
			"In7.Cu" "In8.Cu" "In9.Cu" "In10.Cu" "In11.Cu" "In12.Cu" "In13.Cu" "In14.Cu"
			"In15.Cu" "In16.Cu"
		)
		(hatch none 0.5)
		(connect_pads
			(clearance 0)
		)
		(min_thickness 0.25)
		(keepout
			(tracks not_allowed)
			(vias allowed)
			(pads allowed)
			(copperpour not_allowed)
			(footprints allowed)
		)
		(placement
			(enabled no)
			(sheetname "")
		)
		(fill
			(thermal_gap 0.5)
			(thermal_bridge_width 0.5)
			(island_removal_mode 0)
		)
		(polygon
			(pts
				(arc
					(start 107.270296 -221.133924)
					(mid 106.612436 -221.133924)
					(end 107.270296 -221.133924)
				)
			)
		)
	)
	(zone
		(layers "F.Cu" "B.Cu" "In1.Cu" "In2.Cu" "In3.Cu" "In4.Cu" "In5.Cu" "In6.Cu"
			"In7.Cu" "In8.Cu" "In9.Cu" "In10.Cu" "In11.Cu" "In12.Cu" "In13.Cu" "In14.Cu"
			"In15.Cu" "In16.Cu"
		)
		(hatch none 0.5)
		(connect_pads
			(clearance 0)
		)
		(min_thickness 0.25)
		(keepout
			(tracks not_allowed)
			(vias allowed)
			(pads allowed)
			(copperpour not_allowed)
			(footprints allowed)
		)
		(placement
			(enabled no)
			(sheetname "")
		)
		(fill
			(thermal_gap 0.5)
			(thermal_bridge_width 0.5)
			(island_removal_mode 0)
		)
		(polygon
			(pts
				(arc
					(start 68.142104 -425.360592)
					(mid 68.164422 -425.414474)
					(end 68.218304 -425.436792)
				)
				(arc
					(start 69.158104 -425.436792)
					(mid 69.211986 -425.414474)
					(end 69.234304 -425.360592)
				)
				(arc
					(start 69.234304 -422.819068)
					(mid 69.211986 -422.765186)
					(end 69.158104 -422.742868)
				)
				(arc
					(start 68.218304 -422.742868)
					(mid 68.164422 -422.765186)
					(end 68.142104 -422.819068)
				)
			)
		)
	)
	(zone
		(layers "F.Cu" "B.Cu" "In1.Cu" "In2.Cu" "In3.Cu" "In4.Cu" "In5.Cu" "In6.Cu"
			"In7.Cu" "In8.Cu" "In9.Cu" "In10.Cu" "In11.Cu" "In12.Cu" "In13.Cu" "In14.Cu"
			"In15.Cu" "In16.Cu"
		)
		(hatch none 0.5)
		(connect_pads
			(clearance 0)
		)
		(min_thickness 0.25)
		(keepout
			(tracks not_allowed)
			(vias allowed)
			(pads allowed)
			(copperpour not_allowed)
			(footprints allowed)
		)
		(placement
			(enabled no)
			(sheetname "")
		)
		(fill
			(thermal_gap 0.5)
			(thermal_bridge_width 0.5)
			(island_removal_mode 0)
		)
		(polygon
			(pts
				(arc
					(start 354.270564 -217.878406)
					(mid 353.612704 -217.878406)
					(end 354.270564 -217.878406)
				)
			)
		)
	)
	(zone
		(layers "F.Cu" "B.Cu" "In1.Cu" "In2.Cu" "In3.Cu" "In4.Cu" "In5.Cu" "In6.Cu"
			"In7.Cu" "In8.Cu" "In9.Cu" "In10.Cu" "In11.Cu" "In12.Cu" "In13.Cu" "In14.Cu"
			"In15.Cu" "In16.Cu"
		)
		(hatch none 0.5)
		(connect_pads
			(clearance 0)
		)
		(min_thickness 0.25)
		(keepout
			(tracks not_allowed)
			(vias allowed)
			(pads allowed)
			(copperpour not_allowed)
			(footprints allowed)
		)
		(placement
			(enabled no)
			(sheetname "")
		)
		(fill
			(thermal_gap 0.5)
			(thermal_bridge_width 0.5)
			(island_removal_mode 0)
		)
		(polygon
			(pts
				(arc
					(start 358.49941 -225.203258)
					(mid 357.84155 -225.203258)
					(end 358.49941 -225.203258)
				)
			)
		)
	)
	(zone
		(layers "F.Cu" "B.Cu" "In1.Cu" "In2.Cu" "In3.Cu" "In4.Cu" "In5.Cu" "In6.Cu"
			"In7.Cu" "In8.Cu" "In9.Cu" "In10.Cu" "In11.Cu" "In12.Cu" "In13.Cu" "In14.Cu"
			"In15.Cu" "In16.Cu"
		)
		(hatch none 0.5)
		(connect_pads
			(clearance 0)
		)
		(min_thickness 0.25)
		(keepout
			(tracks not_allowed)
			(vias allowed)
			(pads allowed)
			(copperpour not_allowed)
			(footprints allowed)
		)
		(placement
			(enabled no)
			(sheetname "")
		)
		(fill
			(thermal_gap 0.5)
			(thermal_bridge_width 0.5)
			(island_removal_mode 0)
		)
		(polygon
			(pts
				(arc
					(start 368.20856 -217.97645)
					(mid 368.228244 -217.92904)
					(end 368.234976 -217.878152)
				)
				(arc
					(start 368.234976 -217.878152)
					(mid 368.17732 -217.738958)
					(end 368.038126 -217.681302)
				)
				(arc
					(start 368.038126 -217.681302)
					(mid 367.939695 -217.707718)
					(end 367.867692 -217.779854)
				)
				(arc
					(start 367.398046 -218.593924)
					(mid 367.378362 -218.641334)
					(end 367.37163 -218.692222)
				)
				(arc
					(start 367.37163 -218.692222)
					(mid 367.429286 -218.831416)
					(end 367.56848 -218.889072)
				)
				(arc
					(start 367.56848 -218.889072)
					(mid 367.666911 -218.862656)
					(end 367.738914 -218.79052)
				)
			)
		)
	)
	(zone
		(layers "F.Cu" "B.Cu" "In1.Cu" "In2.Cu" "In3.Cu" "In4.Cu" "In5.Cu" "In6.Cu"
			"In7.Cu" "In8.Cu" "In9.Cu" "In10.Cu" "In11.Cu" "In12.Cu" "In13.Cu" "In14.Cu"
			"In15.Cu" "In16.Cu"
		)
		(hatch none 0.5)
		(connect_pads
			(clearance 0)
		)
		(min_thickness 0.25)
		(keepout
			(tracks not_allowed)
			(vias allowed)
			(pads allowed)
			(copperpour not_allowed)
			(footprints allowed)
		)
		(placement
			(enabled no)
			(sheetname "")
		)
		(fill
			(thermal_gap 0.5)
			(thermal_bridge_width 0.5)
			(island_removal_mode 0)
		)
		(polygon
			(pts
				(arc
					(start 345.34221 -221.94774)
					(mid 344.68435 -221.94774)
					(end 345.34221 -221.94774)
				)
			)
		)
	)
	(zone
		(layers "F.Cu" "B.Cu" "In1.Cu" "In2.Cu" "In3.Cu" "In4.Cu" "In5.Cu" "In6.Cu"
			"In7.Cu" "In8.Cu" "In9.Cu" "In10.Cu" "In11.Cu" "In12.Cu" "In13.Cu" "In14.Cu"
			"In15.Cu" "In16.Cu"
		)
		(hatch none 0.5)
		(connect_pads
			(clearance 0)
		)
		(min_thickness 0.25)
		(keepout
			(tracks not_allowed)
			(vias allowed)
			(pads allowed)
			(copperpour not_allowed)
			(footprints allowed)
		)
		(placement
			(enabled no)
			(sheetname "")
		)
		(fill
			(thermal_gap 0.5)
			(thermal_bridge_width 0.5)
			(island_removal_mode 0)
		)
		(polygon
			(pts
				(arc
					(start 156.736542 -44.788836)
					(mid 156.355542 -44.407836)
					(end 155.974542 -44.788836)
				)
				(arc
					(start 155.974542 -45.652436)
					(mid 156.355542 -46.033436)
					(end 156.736542 -45.652436)
				)
			)
		)
	)
	(zone
		(layers "F.Cu" "B.Cu" "In1.Cu" "In2.Cu" "In3.Cu" "In4.Cu" "In5.Cu" "In6.Cu"
			"In7.Cu" "In8.Cu" "In9.Cu" "In10.Cu" "In11.Cu" "In12.Cu" "In13.Cu" "In14.Cu"
			"In15.Cu" "In16.Cu"
		)
		(hatch none 0.5)
		(connect_pads
			(clearance 0)
		)
		(min_thickness 0.25)
		(keepout
			(tracks not_allowed)
			(vias allowed)
			(pads allowed)
			(copperpour not_allowed)
			(footprints allowed)
		)
		(placement
			(enabled no)
			(sheetname "")
		)
		(fill
			(thermal_gap 0.5)
			(thermal_bridge_width 0.5)
			(island_removal_mode 0)
		)
		(polygon
			(pts
				(arc
					(start 386.73913 -400.477228)
					(mid 386.35813 -400.858228)
					(end 386.73913 -401.239228)
				)
				(arc
					(start 387.60273 -401.239228)
					(mid 387.98373 -400.858228)
					(end 387.60273 -400.477228)
				)
			)
		)
	)
	(zone
		(layers "F.Cu" "B.Cu" "In1.Cu" "In2.Cu" "In3.Cu" "In4.Cu" "In5.Cu" "In6.Cu"
			"In7.Cu" "In8.Cu" "In9.Cu" "In10.Cu" "In11.Cu" "In12.Cu" "In13.Cu" "In14.Cu"
			"In15.Cu" "In16.Cu"
		)
		(hatch none 0.5)
		(connect_pads
			(clearance 0)
		)
		(min_thickness 0.25)
		(keepout
			(tracks not_allowed)
			(vias allowed)
			(pads allowed)
			(copperpour not_allowed)
			(footprints allowed)
		)
		(placement
			(enabled no)
			(sheetname "")
		)
		(fill
			(thermal_gap 0.5)
			(thermal_bridge_width 0.5)
			(island_removal_mode 0)
		)
		(polygon
			(pts
				(arc
					(start 377.765564 -221.133924)
					(mid 377.107704 -221.133924)
					(end 377.765564 -221.133924)
				)
			)
		)
	)
	(zone
		(layers "F.Cu" "B.Cu" "In1.Cu" "In2.Cu" "In3.Cu" "In4.Cu" "In5.Cu" "In6.Cu"
			"In7.Cu" "In8.Cu" "In9.Cu" "In10.Cu" "In11.Cu" "In12.Cu" "In13.Cu" "In14.Cu"
			"In15.Cu" "In16.Cu"
		)
		(hatch none 0.5)
		(connect_pads
			(clearance 0)
		)
		(min_thickness 0.25)
		(keepout
			(tracks not_allowed)
			(vias allowed)
			(pads allowed)
			(copperpour not_allowed)
			(footprints allowed)
		)
		(placement
			(enabled no)
			(sheetname "")
		)
		(fill
			(thermal_gap 0.5)
			(thermal_bridge_width 0.5)
			(island_removal_mode 0)
		)
		(polygon
			(pts
				(arc
					(start 359.750868 -224.291144)
					(mid 359.678879 -224.218985)
					(end 359.580434 -224.192592)
				)
				(arc
					(start 359.580434 -224.192592)
					(mid 359.44124 -224.250248)
					(end 359.383584 -224.389442)
				)
				(arc
					(start 359.383584 -224.389442)
					(mid 359.390341 -224.440323)
					(end 359.41 -224.48774)
				)
				(arc
					(start 359.879646 -225.301556)
					(mid 359.951635 -225.373715)
					(end 360.05008 -225.400108)
				)
				(arc
					(start 360.05008 -225.400108)
					(mid 360.189274 -225.342452)
					(end 360.24693 -225.203258)
				)
				(arc
					(start 360.24693 -225.203258)
					(mid 360.240173 -225.152377)
					(end 360.220514 -225.10496)
				)
			)
		)
	)
	(zone
		(layers "F.Cu" "B.Cu" "In1.Cu" "In2.Cu" "In3.Cu" "In4.Cu" "In5.Cu" "In6.Cu"
			"In7.Cu" "In8.Cu" "In9.Cu" "In10.Cu" "In11.Cu" "In12.Cu" "In13.Cu" "In14.Cu"
			"In15.Cu" "In16.Cu"
		)
		(hatch none 0.5)
		(connect_pads
			(clearance 0)
		)
		(min_thickness 0.25)
		(keepout
			(tracks not_allowed)
			(vias allowed)
			(pads allowed)
			(copperpour not_allowed)
			(footprints allowed)
		)
		(placement
			(enabled no)
			(sheetname "")
		)
		(fill
			(thermal_gap 0.5)
			(thermal_bridge_width 0.5)
			(island_removal_mode 0)
		)
		(polygon
			(pts
				(arc
					(start 93.0148 -217.780108)
					(mid 92.942811 -217.707949)
					(end 92.844366 -217.681556)
				)
				(arc
					(start 92.844366 -217.681556)
					(mid 92.705172 -217.739212)
					(end 92.647516 -217.878406)
				)
				(arc
					(start 92.647516 -217.878406)
					(mid 92.654273 -217.929287)
					(end 92.673932 -217.976704)
				)
				(arc
					(start 93.143578 -218.79052)
					(mid 93.215567 -218.862679)
					(end 93.314012 -218.889072)
				)
				(arc
					(start 93.314012 -218.889072)
					(mid 93.453206 -218.831416)
					(end 93.510862 -218.692222)
				)
				(arc
					(start 93.510862 -218.692222)
					(mid 93.504105 -218.641341)
					(end 93.484446 -218.593924)
				)
			)
		)
	)
	(zone
		(layers "F.Cu" "B.Cu" "In1.Cu" "In2.Cu" "In3.Cu" "In4.Cu" "In5.Cu" "In6.Cu"
			"In7.Cu" "In8.Cu" "In9.Cu" "In10.Cu" "In11.Cu" "In12.Cu" "In13.Cu" "In14.Cu"
			"In15.Cu" "In16.Cu"
		)
		(hatch none 0.5)
		(connect_pads
			(clearance 0)
		)
		(min_thickness 0.25)
		(keepout
			(tracks not_allowed)
			(vias allowed)
			(pads allowed)
			(copperpour not_allowed)
			(footprints allowed)
		)
		(placement
			(enabled no)
			(sheetname "")
		)
		(fill
			(thermal_gap 0.5)
			(thermal_bridge_width 0.5)
			(island_removal_mode 0)
		)
		(polygon
			(pts
				(arc
					(start 81.675478 -400.477228)
					(mid 81.294478 -400.858228)
					(end 81.675478 -401.239228)
				)
				(arc
					(start 82.539078 -401.239228)
					(mid 82.920078 -400.858228)
					(end 82.539078 -400.477228)
				)
			)
		)
	)
	(zone
		(layers "F.Cu" "B.Cu" "In1.Cu" "In2.Cu" "In3.Cu" "In4.Cu" "In5.Cu" "In6.Cu"
			"In7.Cu" "In8.Cu" "In9.Cu" "In10.Cu" "In11.Cu" "In12.Cu" "In13.Cu" "In14.Cu"
			"In15.Cu" "In16.Cu"
		)
		(hatch none 0.5)
		(connect_pads
			(clearance 0)
		)
		(min_thickness 0.25)
		(keepout
			(tracks not_allowed)
			(vias allowed)
			(pads allowed)
			(copperpour not_allowed)
			(footprints allowed)
		)
		(placement
			(enabled no)
			(sheetname "")
		)
		(fill
			(thermal_gap 0.5)
			(thermal_bridge_width 0.5)
			(island_removal_mode 0)
		)
		(polygon
			(pts
				(arc
					(start 15.708884 -27.62885)
					(mid 12.799881 -27.725561)
					(end 12.896596 -30.634432)
				)
				(arc
					(start 14.064996 -31.727394)
					(mid 16.973863 -31.630811)
					(end 16.877284 -28.721812)
				)
			)
		)
	)
	(zone
		(layers "F.Cu" "B.Cu" "In1.Cu" "In2.Cu" "In3.Cu" "In4.Cu" "In5.Cu" "In6.Cu"
			"In7.Cu" "In8.Cu" "In9.Cu" "In10.Cu" "In11.Cu" "In12.Cu" "In13.Cu" "In14.Cu"
			"In15.Cu" "In16.Cu"
		)
		(hatch none 0.5)
		(connect_pads
			(clearance 0)
		)
		(min_thickness 0.25)
		(keepout
			(tracks not_allowed)
			(vias allowed)
			(pads allowed)
			(copperpour not_allowed)
			(footprints allowed)
		)
		(placement
			(enabled no)
			(sheetname "")
		)
		(fill
			(thermal_gap 0.5)
			(thermal_bridge_width 0.5)
			(island_removal_mode 0)
		)
		(polygon
			(pts
				(arc
					(start 412.59125 -409.649168)
					(mid 412.21025 -410.030168)
					(end 412.59125 -410.411168)
				)
				(arc
					(start 413.45485 -410.411168)
					(mid 413.83585 -410.030168)
					(end 413.45485 -409.649168)
				)
			)
		)
	)
	(zone
		(layers "F.Cu" "B.Cu" "In1.Cu" "In2.Cu" "In3.Cu" "In4.Cu" "In5.Cu" "In6.Cu"
			"In7.Cu" "In8.Cu" "In9.Cu" "In10.Cu" "In11.Cu" "In12.Cu" "In13.Cu" "In14.Cu"
			"In15.Cu" "In16.Cu"
		)
		(hatch none 0.5)
		(connect_pads
			(clearance 0)
		)
		(min_thickness 0.25)
		(keepout
			(tracks not_allowed)
			(vias allowed)
			(pads allowed)
			(copperpour not_allowed)
			(footprints allowed)
		)
		(placement
			(enabled no)
			(sheetname "")
		)
		(fill
			(thermal_gap 0.5)
			(thermal_bridge_width 0.5)
			(island_removal_mode 0)
		)
		(polygon
			(pts
				(arc
					(start 347.17355 -285.563056)
					(mid 347.101561 -285.490897)
					(end 347.003116 -285.464504)
				)
				(arc
					(start 347.003116 -285.464504)
					(mid 346.863922 -285.52216)
					(end 346.806266 -285.661354)
				)
				(arc
					(start 346.806266 -285.661354)
					(mid 346.813023 -285.712235)
					(end 346.832682 -285.759652)
				)
				(arc
					(start 347.302582 -286.573722)
					(mid 347.374571 -286.645881)
					(end 347.473016 -286.672274)
				)
				(arc
					(start 347.473016 -286.672274)
					(mid 347.61221 -286.614618)
					(end 347.669866 -286.475424)
				)
				(arc
					(start 347.669866 -286.475424)
					(mid 347.663109 -286.424543)
					(end 347.64345 -286.377126)
				)
			)
		)
	)
	(zone
		(layers "F.Cu" "B.Cu" "In1.Cu" "In2.Cu" "In3.Cu" "In4.Cu" "In5.Cu" "In6.Cu"
			"In7.Cu" "In8.Cu" "In9.Cu" "In10.Cu" "In11.Cu" "In12.Cu" "In13.Cu" "In14.Cu"
			"In15.Cu" "In16.Cu"
		)
		(hatch none 0.5)
		(connect_pads
			(clearance 0)
		)
		(min_thickness 0.25)
		(keepout
			(tracks not_allowed)
			(vias allowed)
			(pads allowed)
			(copperpour not_allowed)
			(footprints allowed)
		)
		(placement
			(enabled no)
			(sheetname "")
		)
		(fill
			(thermal_gap 0.5)
			(thermal_bridge_width 0.5)
			(island_removal_mode 0)
		)
		(polygon
			(pts
				(arc
					(start 346.593668 -224.291144)
					(mid 346.521679 -224.218985)
					(end 346.423234 -224.192592)
				)
				(arc
					(start 346.423234 -224.192592)
					(mid 346.28404 -224.250248)
					(end 346.226384 -224.389442)
				)
				(arc
					(start 346.226384 -224.389442)
					(mid 346.233141 -224.440323)
					(end 346.2528 -224.48774)
				)
				(arc
					(start 346.722446 -225.301556)
					(mid 346.794435 -225.373715)
					(end 346.89288 -225.400108)
				)
				(arc
					(start 346.89288 -225.400108)
					(mid 347.032074 -225.342452)
					(end 347.08973 -225.203258)
				)
				(arc
					(start 347.08973 -225.203258)
					(mid 347.082973 -225.152377)
					(end 347.063314 -225.10496)
				)
			)
		)
	)
	(zone
		(layers "F.Cu" "B.Cu" "In1.Cu" "In2.Cu" "In3.Cu" "In4.Cu" "In5.Cu" "In6.Cu"
			"In7.Cu" "In8.Cu" "In9.Cu" "In10.Cu" "In11.Cu" "In12.Cu" "In13.Cu" "In14.Cu"
			"In15.Cu" "In16.Cu"
		)
		(hatch none 0.5)
		(connect_pads
			(clearance 0)
		)
		(min_thickness 0.25)
		(keepout
			(tracks not_allowed)
			(vias allowed)
			(pads allowed)
			(copperpour not_allowed)
			(footprints allowed)
		)
		(placement
			(enabled no)
			(sheetname "")
		)
		(fill
			(thermal_gap 0.5)
			(thermal_bridge_width 0.5)
			(island_removal_mode 0)
		)
		(polygon
			(pts
				(arc
					(start 133.694678 -286.475424)
					(mid 133.036818 -286.475424)
					(end 133.694678 -286.475424)
				)
			)
		)
	)
	(zone
		(layers "F.Cu" "B.Cu" "In1.Cu" "In2.Cu" "In3.Cu" "In4.Cu" "In5.Cu" "In6.Cu"
			"In7.Cu" "In8.Cu" "In9.Cu" "In10.Cu" "In11.Cu" "In12.Cu" "In13.Cu" "In14.Cu"
			"In15.Cu" "In16.Cu"
		)
		(hatch none 0.5)
		(connect_pads
			(clearance 0)
		)
		(min_thickness 0.25)
		(keepout
			(tracks not_allowed)
			(vias allowed)
			(pads allowed)
			(copperpour not_allowed)
			(footprints allowed)
		)
		(placement
			(enabled no)
			(sheetname "")
		)
		(fill
			(thermal_gap 0.5)
			(thermal_bridge_width 0.5)
			(island_removal_mode 0)
		)
		(polygon
			(pts
				(arc
					(start 105.202482 -220.319854)
					(mid 105.860342 -220.319854)
					(end 105.202482 -220.319854)
				)
			)
		)
	)
	(zone
		(layers "F.Cu" "B.Cu" "In1.Cu" "In2.Cu" "In3.Cu" "In4.Cu" "In5.Cu" "In6.Cu"
			"In7.Cu" "In8.Cu" "In9.Cu" "In10.Cu" "In11.Cu" "In12.Cu" "In13.Cu" "In14.Cu"
			"In15.Cu" "In16.Cu"
		)
		(hatch none 0.5)
		(connect_pads
			(clearance 0)
		)
		(min_thickness 0.25)
		(keepout
			(tracks not_allowed)
			(vias allowed)
			(pads allowed)
			(copperpour not_allowed)
			(footprints allowed)
		)
		(placement
			(enabled no)
			(sheetname "")
		)
		(fill
			(thermal_gap 0.5)
			(thermal_bridge_width 0.5)
			(island_removal_mode 0)
		)
		(polygon
			(pts
				(arc
					(start 120.897396 -213.732618)
					(mid 120.239536 -213.732618)
					(end 120.897396 -213.732618)
				)
			)
		)
	)
	(zone
		(layers "F.Cu" "B.Cu" "In1.Cu" "In2.Cu" "In3.Cu" "In4.Cu" "In5.Cu" "In6.Cu"
			"In7.Cu" "In8.Cu" "In9.Cu" "In10.Cu" "In11.Cu" "In12.Cu" "In13.Cu" "In14.Cu"
			"In15.Cu" "In16.Cu"
		)
		(hatch none 0.5)
		(connect_pads
			(clearance 0)
		)
		(min_thickness 0.25)
		(keepout
			(tracks not_allowed)
			(vias allowed)
			(pads allowed)
			(copperpour not_allowed)
			(footprints allowed)
		)
		(placement
			(enabled no)
			(sheetname "")
		)
		(fill
			(thermal_gap 0.5)
			(thermal_bridge_width 0.5)
			(island_removal_mode 0)
		)
		(polygon
			(pts
				(arc
					(start 379.17501 -218.692222)
					(mid 378.51715 -218.692222)
					(end 379.17501 -218.692222)
				)
			)
		)
	)
	(zone
		(layers "F.Cu" "B.Cu" "In1.Cu" "In2.Cu" "In3.Cu" "In4.Cu" "In5.Cu" "In6.Cu"
			"In7.Cu" "In8.Cu" "In9.Cu" "In10.Cu" "In11.Cu" "In12.Cu" "In13.Cu" "In14.Cu"
			"In15.Cu" "In16.Cu"
		)
		(hatch none 0.5)
		(connect_pads
			(clearance 0)
		)
		(min_thickness 0.25)
		(keepout
			(tracks not_allowed)
			(vias allowed)
			(pads allowed)
			(copperpour not_allowed)
			(footprints allowed)
		)
		(placement
			(enabled no)
			(sheetname "")
		)
		(fill
			(thermal_gap 0.5)
			(thermal_bridge_width 0.5)
			(island_removal_mode 0)
		)
		(polygon
			(pts
				(arc
					(start 40.73144 -4.581652)
					(mid 40.35044 -4.962652)
					(end 40.73144 -5.343652)
				)
				(arc
					(start 41.59504 -5.343652)
					(mid 41.97604 -4.962652)
					(end 41.59504 -4.581652)
				)
			)
		)
	)
	(zone
		(layers "F.Cu" "B.Cu" "In1.Cu" "In2.Cu" "In3.Cu" "In4.Cu" "In5.Cu" "In6.Cu"
			"In7.Cu" "In8.Cu" "In9.Cu" "In10.Cu" "In11.Cu" "In12.Cu" "In13.Cu" "In14.Cu"
			"In15.Cu" "In16.Cu"
		)
		(hatch none 0.5)
		(connect_pads
			(clearance 0)
		)
		(min_thickness 0.25)
		(keepout
			(tracks not_allowed)
			(vias allowed)
			(pads allowed)
			(copperpour not_allowed)
			(footprints allowed)
		)
		(placement
			(enabled no)
			(sheetname "")
		)
		(fill
			(thermal_gap 0.5)
			(thermal_bridge_width 0.5)
			(island_removal_mode 0)
		)
		(polygon
			(pts
				(arc
					(start 414.30829 -400.477228)
					(mid 413.92729 -400.858228)
					(end 414.30829 -401.239228)
				)
				(arc
					(start 415.17189 -401.239228)
					(mid 415.55289 -400.858228)
					(end 415.17189 -400.477228)
				)
			)
		)
	)
	(zone
		(layers "F.Cu" "B.Cu" "In1.Cu" "In2.Cu" "In3.Cu" "In4.Cu" "In5.Cu" "In6.Cu"
			"In7.Cu" "In8.Cu" "In9.Cu" "In10.Cu" "In11.Cu" "In12.Cu" "In13.Cu" "In14.Cu"
			"In15.Cu" "In16.Cu"
		)
		(hatch none 0.5)
		(connect_pads
			(clearance 0)
		)
		(min_thickness 0.25)
		(keepout
			(tracks not_allowed)
			(vias allowed)
			(pads allowed)
			(copperpour not_allowed)
			(footprints allowed)
		)
		(placement
			(enabled no)
			(sheetname "")
		)
		(fill
			(thermal_gap 0.5)
			(thermal_bridge_width 0.5)
			(island_removal_mode 0)
		)
		(polygon
			(pts
				(arc
					(start 351.732342 -69.10578)
					(mid 352.113342 -69.48678)
					(end 352.494342 -69.10578)
				)
				(arc
					(start 352.494342 -68.24218)
					(mid 352.113342 -67.86118)
					(end 351.732342 -68.24218)
				)
			)
		)
	)
	(zone
		(layers "F.Cu" "B.Cu" "In1.Cu" "In2.Cu" "In3.Cu" "In4.Cu" "In5.Cu" "In6.Cu"
			"In7.Cu" "In8.Cu" "In9.Cu" "In10.Cu" "In11.Cu" "In12.Cu" "In13.Cu" "In14.Cu"
			"In15.Cu" "In16.Cu"
		)
		(hatch none 0.5)
		(connect_pads
			(clearance 0)
		)
		(min_thickness 0.25)
		(keepout
			(tracks not_allowed)
			(vias allowed)
			(pads allowed)
			(copperpour not_allowed)
			(footprints allowed)
		)
		(placement
			(enabled no)
			(sheetname "")
		)
		(fill
			(thermal_gap 0.5)
			(thermal_bridge_width 0.5)
			(island_removal_mode 0)
		)
		(polygon
			(pts
				(arc
					(start 129.825496 -221.133924)
					(mid 129.167636 -221.133924)
					(end 129.825496 -221.133924)
				)
			)
		)
	)
	(zone
		(layers "F.Cu" "B.Cu" "In1.Cu" "In2.Cu" "In3.Cu" "In4.Cu" "In5.Cu" "In6.Cu"
			"In7.Cu" "In8.Cu" "In9.Cu" "In10.Cu" "In11.Cu" "In12.Cu" "In13.Cu" "In14.Cu"
			"In15.Cu" "In16.Cu"
		)
		(hatch none 0.5)
		(connect_pads
			(clearance 0)
		)
		(min_thickness 0.25)
		(keepout
			(tracks not_allowed)
			(vias allowed)
			(pads allowed)
			(copperpour not_allowed)
			(footprints allowed)
		)
		(placement
			(enabled no)
			(sheetname "")
		)
		(fill
			(thermal_gap 0.5)
			(thermal_bridge_width 0.5)
			(island_removal_mode 0)
		)
		(polygon
			(pts
				(arc
					(start 136.817354 -406.62352)
					(mid 136.436354 -407.00452)
					(end 136.817354 -407.38552)
				)
				(arc
					(start 137.680954 -407.38552)
					(mid 138.061954 -407.00452)
					(end 137.680954 -406.62352)
				)
			)
		)
	)
	(zone
		(layers "F.Cu" "B.Cu" "In1.Cu" "In2.Cu" "In3.Cu" "In4.Cu" "In5.Cu" "In6.Cu"
			"In7.Cu" "In8.Cu" "In9.Cu" "In10.Cu" "In11.Cu" "In12.Cu" "In13.Cu" "In14.Cu"
			"In15.Cu" "In16.Cu"
		)
		(hatch none 0.5)
		(connect_pads
			(clearance 0)
		)
		(min_thickness 0.25)
		(keepout
			(tracks not_allowed)
			(vias allowed)
			(pads allowed)
			(copperpour not_allowed)
			(footprints allowed)
		)
		(placement
			(enabled no)
			(sheetname "")
		)
		(fill
			(thermal_gap 0.5)
			(thermal_bridge_width 0.5)
			(island_removal_mode 0)
		)
		(polygon
			(pts
				(arc
					(start 90.865198 -403.502876)
					(mid 90.484198 -403.883876)
					(end 90.865198 -404.264876)
				)
				(arc
					(start 91.728798 -404.264876)
					(mid 92.109798 -403.883876)
					(end 91.728798 -403.502876)
				)
			)
		)
	)
	(zone
		(layers "F.Cu" "B.Cu" "In1.Cu" "In2.Cu" "In3.Cu" "In4.Cu" "In5.Cu" "In6.Cu"
			"In7.Cu" "In8.Cu" "In9.Cu" "In10.Cu" "In11.Cu" "In12.Cu" "In13.Cu" "In14.Cu"
			"In15.Cu" "In16.Cu"
		)
		(hatch none 0.5)
		(connect_pads
			(clearance 0)
		)
		(min_thickness 0.25)
		(keepout
			(tracks not_allowed)
			(vias allowed)
			(pads allowed)
			(copperpour not_allowed)
			(footprints allowed)
		)
		(placement
			(enabled no)
			(sheetname "")
		)
		(fill
			(thermal_gap 0.5)
			(thermal_bridge_width 0.5)
			(island_removal_mode 0)
		)
		(polygon
			(pts
				(arc
					(start 115.540282 -215.436704)
					(mid 116.198142 -215.436704)
					(end 115.540282 -215.436704)
				)
			)
		)
	)
	(zone
		(layers "F.Cu" "B.Cu" "In1.Cu" "In2.Cu" "In3.Cu" "In4.Cu" "In5.Cu" "In6.Cu"
			"In7.Cu" "In8.Cu" "In9.Cu" "In10.Cu" "In11.Cu" "In12.Cu" "In13.Cu" "In14.Cu"
			"In15.Cu" "In16.Cu"
		)
		(hatch none 0.5)
		(connect_pads
			(clearance 0)
		)
		(min_thickness 0.25)
		(keepout
			(tracks not_allowed)
			(vias allowed)
			(pads allowed)
			(copperpour not_allowed)
			(footprints allowed)
		)
		(placement
			(enabled no)
			(sheetname "")
		)
		(fill
			(thermal_gap 0.5)
			(thermal_bridge_width 0.5)
			(island_removal_mode 0)
		)
		(polygon
			(pts
				(arc
					(start 135.61441 -14.813788)
					(mid 135.23341 -15.194788)
					(end 135.61441 -15.575788)
				)
				(arc
					(start 136.47801 -15.575788)
					(mid 136.85901 -15.194788)
					(end 136.47801 -14.813788)
				)
			)
		)
	)
	(zone
		(layers "F.Cu" "B.Cu" "In1.Cu" "In2.Cu" "In3.Cu" "In4.Cu" "In5.Cu" "In6.Cu"
			"In7.Cu" "In8.Cu" "In9.Cu" "In10.Cu" "In11.Cu" "In12.Cu" "In13.Cu" "In14.Cu"
			"In15.Cu" "In16.Cu"
		)
		(hatch none 0.5)
		(connect_pads
			(clearance 0)
		)
		(min_thickness 0.25)
		(keepout
			(tracks not_allowed)
			(vias allowed)
			(pads allowed)
			(copperpour not_allowed)
			(footprints allowed)
		)
		(placement
			(enabled no)
			(sheetname "")
		)
		(fill
			(thermal_gap 0.5)
			(thermal_bridge_width 0.5)
			(island_removal_mode 0)
		)
		(polygon
			(pts
				(arc
					(start 93.172788 -214.622634)
					(mid 92.514928 -214.622634)
					(end 93.172788 -214.622634)
				)
			)
		)
	)
	(zone
		(layers "F.Cu" "B.Cu" "In1.Cu" "In2.Cu" "In3.Cu" "In4.Cu" "In5.Cu" "In6.Cu"
			"In7.Cu" "In8.Cu" "In9.Cu" "In10.Cu" "In11.Cu" "In12.Cu" "In13.Cu" "In14.Cu"
			"In15.Cu" "In16.Cu"
		)
		(hatch none 0.5)
		(connect_pads
			(clearance 0)
		)
		(min_thickness 0.25)
		(keepout
			(tracks not_allowed)
			(vias allowed)
			(pads allowed)
			(copperpour not_allowed)
			(footprints allowed)
		)
		(placement
			(enabled no)
			(sheetname "")
		)
		(fill
			(thermal_gap 0.5)
			(thermal_bridge_width 0.5)
			(island_removal_mode 0)
		)
		(polygon
			(pts
				(arc
					(start 415.238946 -4.57073)
					(mid 414.857946 -4.95173)
					(end 415.238946 -5.33273)
				)
				(arc
					(start 416.102546 -5.33273)
					(mid 416.483546 -4.95173)
					(end 416.102546 -4.57073)
				)
			)
		)
	)
	(zone
		(layers "F.Cu" "B.Cu" "In1.Cu" "In2.Cu" "In3.Cu" "In4.Cu" "In5.Cu" "In6.Cu"
			"In7.Cu" "In8.Cu" "In9.Cu" "In10.Cu" "In11.Cu" "In12.Cu" "In13.Cu" "In14.Cu"
			"In15.Cu" "In16.Cu"
		)
		(hatch none 0.5)
		(connect_pads
			(clearance 0)
		)
		(min_thickness 0.25)
		(keepout
			(tracks not_allowed)
			(vias allowed)
			(pads allowed)
			(copperpour not_allowed)
			(footprints allowed)
		)
		(placement
			(enabled no)
			(sheetname "")
		)
		(fill
			(thermal_gap 0.5)
			(thermal_bridge_width 0.5)
			(island_removal_mode 0)
		)
		(polygon
			(pts
				(arc
					(start 424.644312 -6.332474)
					(mid 424.263312 -6.713474)
					(end 424.644312 -7.094474)
				)
				(arc
					(start 425.507912 -7.094474)
					(mid 425.888912 -6.713474)
					(end 425.507912 -6.332474)
				)
			)
		)
	)
	(zone
		(layers "F.Cu" "B.Cu" "In1.Cu" "In2.Cu" "In3.Cu" "In4.Cu" "In5.Cu" "In6.Cu"
			"In7.Cu" "In8.Cu" "In9.Cu" "In10.Cu" "In11.Cu" "In12.Cu" "In13.Cu" "In14.Cu"
			"In15.Cu" "In16.Cu"
		)
		(hatch none 0.5)
		(connect_pads
			(clearance 0)
		)
		(min_thickness 0.25)
		(keepout
			(tracks not_allowed)
			(vias allowed)
			(pads allowed)
			(copperpour not_allowed)
			(footprints allowed)
		)
		(placement
			(enabled no)
			(sheetname "")
		)
		(fill
			(thermal_gap 0.5)
			(thermal_bridge_width 0.5)
			(island_removal_mode 0)
		)
		(polygon
			(pts
				(arc
					(start 37.885878 -17.23136)
					(mid 37.504878 -17.61236)
					(end 37.885878 -17.99336)
				)
				(arc
					(start 38.749478 -17.99336)
					(mid 39.130478 -17.61236)
					(end 38.749478 -17.23136)
				)
			)
		)
	)
	(zone
		(layers "F.Cu" "B.Cu" "In1.Cu" "In2.Cu" "In3.Cu" "In4.Cu" "In5.Cu" "In6.Cu"
			"In7.Cu" "In8.Cu" "In9.Cu" "In10.Cu" "In11.Cu" "In12.Cu" "In13.Cu" "In14.Cu"
			"In15.Cu" "In16.Cu"
		)
		(hatch none 0.5)
		(connect_pads
			(clearance 0)
		)
		(min_thickness 0.25)
		(keepout
			(tracks not_allowed)
			(vias allowed)
			(pads allowed)
			(copperpour not_allowed)
			(footprints allowed)
		)
		(placement
			(enabled no)
			(sheetname "")
		)
		(fill
			(thermal_gap 0.5)
			(thermal_bridge_width 0.5)
			(island_removal_mode 0)
		)
		(polygon
			(pts
				(arc
					(start 105.390188 -214.622634)
					(mid 104.732328 -214.622634)
					(end 105.390188 -214.622634)
				)
			)
		)
	)
	(zone
		(layers "F.Cu" "B.Cu" "In1.Cu" "In2.Cu" "In3.Cu" "In4.Cu" "In5.Cu" "In6.Cu"
			"In7.Cu" "In8.Cu" "In9.Cu" "In10.Cu" "In11.Cu" "In12.Cu" "In13.Cu" "In14.Cu"
			"In15.Cu" "In16.Cu"
		)
		(hatch none 0.5)
		(connect_pads
			(clearance 0)
		)
		(min_thickness 0.25)
		(keepout
			(tracks not_allowed)
			(vias allowed)
			(pads allowed)
			(copperpour not_allowed)
			(footprints allowed)
		)
		(placement
			(enabled no)
			(sheetname "")
		)
		(fill
			(thermal_gap 0.5)
			(thermal_bridge_width 0.5)
			(island_removal_mode 0)
		)
		(polygon
			(pts
				(arc
					(start 262.4963 -97.477834)
					(mid 262.1153 -97.096834)
					(end 261.7343 -97.477834)
				)
				(arc
					(start 261.7343 -98.341434)
					(mid 262.1153 -98.722434)
					(end 262.4963 -98.341434)
				)
			)
		)
	)
	(zone
		(layers "F.Cu" "B.Cu" "In1.Cu" "In2.Cu" "In3.Cu" "In4.Cu" "In5.Cu" "In6.Cu"
			"In7.Cu" "In8.Cu" "In9.Cu" "In10.Cu" "In11.Cu" "In12.Cu" "In13.Cu" "In14.Cu"
			"In15.Cu" "In16.Cu"
		)
		(hatch none 0.5)
		(connect_pads
			(clearance 0)
		)
		(min_thickness 0.25)
		(keepout
			(tracks not_allowed)
			(vias allowed)
			(pads allowed)
			(copperpour not_allowed)
			(footprints allowed)
		)
		(placement
			(enabled no)
			(sheetname "")
		)
		(fill
			(thermal_gap 0.5)
			(thermal_bridge_width 0.5)
			(island_removal_mode 0)
		)
		(polygon
			(pts
				(arc
					(start 362.570014 -221.231968)
					(mid 362.589698 -221.184558)
					(end 362.59643 -221.13367)
				)
				(arc
					(start 362.59643 -221.13367)
					(mid 362.538774 -220.994476)
					(end 362.39958 -220.93682)
				)
				(arc
					(start 362.39958 -220.93682)
					(mid 362.301149 -220.963236)
					(end 362.229146 -221.035372)
				)
				(arc
					(start 361.7595 -221.849442)
					(mid 361.739816 -221.896852)
					(end 361.733084 -221.94774)
				)
				(arc
					(start 361.733084 -221.94774)
					(mid 361.79074 -222.086934)
					(end 361.929934 -222.14459)
				)
				(arc
					(start 361.929934 -222.14459)
					(mid 362.028365 -222.118174)
					(end 362.100368 -222.046038)
				)
			)
		)
	)
	(zone
		(layers "F.Cu" "B.Cu" "In1.Cu" "In2.Cu" "In3.Cu" "In4.Cu" "In5.Cu" "In6.Cu"
			"In7.Cu" "In8.Cu" "In9.Cu" "In10.Cu" "In11.Cu" "In12.Cu" "In13.Cu" "In14.Cu"
			"In15.Cu" "In16.Cu"
		)
		(hatch none 0.5)
		(connect_pads
			(clearance 0)
		)
		(min_thickness 0.25)
		(keepout
			(tracks not_allowed)
			(vias allowed)
			(pads allowed)
			(copperpour not_allowed)
			(footprints allowed)
		)
		(placement
			(enabled no)
			(sheetname "")
		)
		(fill
			(thermal_gap 0.5)
			(thermal_bridge_width 0.5)
			(island_removal_mode 0)
		)
		(polygon
			(pts
				(arc
					(start 349.41256 -214.720932)
					(mid 349.432244 -214.673522)
					(end 349.438976 -214.622634)
				)
				(arc
					(start 349.438976 -214.622634)
					(mid 349.38132 -214.48344)
					(end 349.242126 -214.425784)
				)
				(arc
					(start 349.242126 -214.425784)
					(mid 349.143695 -214.4522)
					(end 349.071692 -214.524336)
				)
				(arc
					(start 348.602046 -215.338406)
					(mid 348.582362 -215.385816)
					(end 348.57563 -215.436704)
				)
				(arc
					(start 348.57563 -215.436704)
					(mid 348.633286 -215.575898)
					(end 348.77248 -215.633554)
				)
				(arc
					(start 348.77248 -215.633554)
					(mid 348.870911 -215.607138)
					(end 348.942914 -215.535002)
				)
			)
		)
	)
	(zone
		(layers "F.Cu" "B.Cu" "In1.Cu" "In2.Cu" "In3.Cu" "In4.Cu" "In5.Cu" "In6.Cu"
			"In7.Cu" "In8.Cu" "In9.Cu" "In10.Cu" "In11.Cu" "In12.Cu" "In13.Cu" "In14.Cu"
			"In15.Cu" "In16.Cu"
		)
		(hatch none 0.5)
		(connect_pads
			(clearance 0)
		)
		(min_thickness 0.25)
		(keepout
			(tracks not_allowed)
			(vias allowed)
			(pads allowed)
			(copperpour not_allowed)
			(footprints allowed)
		)
		(placement
			(enabled no)
			(sheetname "")
		)
		(fill
			(thermal_gap 0.5)
			(thermal_bridge_width 0.5)
			(island_removal_mode 0)
		)
		(polygon
			(pts
				(arc
					(start 98.6536 -217.780108)
					(mid 98.581611 -217.707949)
					(end 98.483166 -217.681556)
				)
				(arc
					(start 98.483166 -217.681556)
					(mid 98.343972 -217.739212)
					(end 98.286316 -217.878406)
				)
				(arc
					(start 98.286316 -217.878406)
					(mid 98.293073 -217.929287)
					(end 98.312732 -217.976704)
				)
				(arc
					(start 98.782378 -218.79052)
					(mid 98.854367 -218.862679)
					(end 98.952812 -218.889072)
				)
				(arc
					(start 98.952812 -218.889072)
					(mid 99.092006 -218.831416)
					(end 99.149662 -218.692222)
				)
				(arc
					(start 99.149662 -218.692222)
					(mid 99.142905 -218.641341)
					(end 99.123246 -218.593924)
				)
			)
		)
	)
	(zone
		(layers "F.Cu" "B.Cu" "In1.Cu" "In2.Cu" "In3.Cu" "In4.Cu" "In5.Cu" "In6.Cu"
			"In7.Cu" "In8.Cu" "In9.Cu" "In10.Cu" "In11.Cu" "In12.Cu" "In13.Cu" "In14.Cu"
			"In15.Cu" "In16.Cu"
		)
		(hatch none 0.5)
		(connect_pads
			(clearance 0)
		)
		(min_thickness 0.25)
		(keepout
			(tracks not_allowed)
			(vias allowed)
			(pads allowed)
			(copperpour not_allowed)
			(footprints allowed)
		)
		(placement
			(enabled no)
			(sheetname "")
		)
		(fill
			(thermal_gap 0.5)
			(thermal_bridge_width 0.5)
			(island_removal_mode 0)
		)
		(polygon
			(pts
				(arc
					(start 349.571564 -217.878406)
					(mid 348.913704 -217.878406)
					(end 349.571564 -217.878406)
				)
			)
		)
	)
	(zone
		(layers "F.Cu" "B.Cu" "In1.Cu" "In2.Cu" "In3.Cu" "In4.Cu" "In5.Cu" "In6.Cu"
			"In7.Cu" "In8.Cu" "In9.Cu" "In10.Cu" "In11.Cu" "In12.Cu" "In13.Cu" "In14.Cu"
			"In15.Cu" "In16.Cu"
		)
		(hatch none 0.5)
		(connect_pads
			(clearance 0)
		)
		(min_thickness 0.25)
		(keepout
			(tracks not_allowed)
			(vias allowed)
			(pads allowed)
			(copperpour not_allowed)
			(footprints allowed)
		)
		(placement
			(enabled no)
			(sheetname "")
		)
		(fill
			(thermal_gap 0.5)
			(thermal_bridge_width 0.5)
			(island_removal_mode 0)
		)
		(polygon
			(pts
				(arc
					(start 337.82381 -218.692222)
					(mid 337.16595 -218.692222)
					(end 337.82381 -218.692222)
				)
			)
		)
	)
	(zone
		(layers "F.Cu" "B.Cu" "In1.Cu" "In2.Cu" "In3.Cu" "In4.Cu" "In5.Cu" "In6.Cu"
			"In7.Cu" "In8.Cu" "In9.Cu" "In10.Cu" "In11.Cu" "In12.Cu" "In13.Cu" "In14.Cu"
			"In15.Cu" "In16.Cu"
		)
		(hatch none 0.5)
		(connect_pads
			(clearance 0)
		)
		(min_thickness 0.25)
		(keepout
			(tracks not_allowed)
			(vias allowed)
			(pads allowed)
			(copperpour not_allowed)
			(footprints allowed)
		)
		(placement
			(enabled no)
			(sheetname "")
		)
		(fill
			(thermal_gap 0.5)
			(thermal_bridge_width 0.5)
			(island_removal_mode 0)
		)
		(polygon
			(pts
				(arc
					(start 94.113096 -221.133924)
					(mid 93.455236 -221.133924)
					(end 94.113096 -221.133924)
				)
			)
		)
	)
	(zone
		(layers "F.Cu" "B.Cu" "In1.Cu" "In2.Cu" "In3.Cu" "In4.Cu" "In5.Cu" "In6.Cu"
			"In7.Cu" "In8.Cu" "In9.Cu" "In10.Cu" "In11.Cu" "In12.Cu" "In13.Cu" "In14.Cu"
			"In15.Cu" "In16.Cu"
		)
		(hatch none 0.5)
		(connect_pads
			(clearance 0)
		)
		(min_thickness 0.25)
		(keepout
			(tracks not_allowed)
			(vias allowed)
			(pads allowed)
			(copperpour not_allowed)
			(footprints allowed)
		)
		(placement
			(enabled no)
			(sheetname "")
		)
		(fill
			(thermal_gap 0.5)
			(thermal_bridge_width 0.5)
			(island_removal_mode 0)
		)
		(polygon
			(pts
				(arc
					(start 96.854264 -285.661354)
					(mid 97.512124 -285.661354)
					(end 96.854264 -285.661354)
				)
			)
		)
	)
	(zone
		(layers "F.Cu" "B.Cu" "In1.Cu" "In2.Cu" "In3.Cu" "In4.Cu" "In5.Cu" "In6.Cu"
			"In7.Cu" "In8.Cu" "In9.Cu" "In10.Cu" "In11.Cu" "In12.Cu" "In13.Cu" "In14.Cu"
			"In15.Cu" "In16.Cu"
		)
		(hatch none 0.5)
		(connect_pads
			(clearance 0)
		)
		(min_thickness 0.25)
		(keepout
			(tracks not_allowed)
			(vias allowed)
			(pads allowed)
			(copperpour not_allowed)
			(footprints allowed)
		)
		(placement
			(enabled no)
			(sheetname "")
		)
		(fill
			(thermal_gap 0.5)
			(thermal_bridge_width 0.5)
			(island_removal_mode 0)
		)
		(polygon
			(pts
				(arc
					(start 334.485996 -286.376872)
					(mid 334.413943 -286.304891)
					(end 334.315562 -286.278574)
				)
				(arc
					(start 334.315562 -286.278574)
					(mid 334.176368 -286.33623)
					(end 334.118712 -286.475424)
				)
				(arc
					(start 334.118712 -286.475424)
					(mid 334.125429 -286.52644)
					(end 334.145128 -286.573976)
				)
				(arc
					(start 334.615028 -287.387792)
					(mid 334.687081 -287.459773)
					(end 334.785462 -287.48609)
				)
				(arc
					(start 334.785462 -287.48609)
					(mid 334.924656 -287.428434)
					(end 334.982312 -287.28924)
				)
				(arc
					(start 334.982312 -287.28924)
					(mid 334.975595 -287.238224)
					(end 334.955896 -287.190688)
				)
			)
		)
	)
	(zone
		(layers "F.Cu" "B.Cu" "In1.Cu" "In2.Cu" "In3.Cu" "In4.Cu" "In5.Cu" "In6.Cu"
			"In7.Cu" "In8.Cu" "In9.Cu" "In10.Cu" "In11.Cu" "In12.Cu" "In13.Cu" "In14.Cu"
			"In15.Cu" "In16.Cu"
		)
		(hatch none 0.5)
		(connect_pads
			(clearance 0)
		)
		(min_thickness 0.25)
		(keepout
			(tracks not_allowed)
			(vias allowed)
			(pads allowed)
			(copperpour not_allowed)
			(footprints allowed)
		)
		(placement
			(enabled no)
			(sheetname "")
		)
		(fill
			(thermal_gap 0.5)
			(thermal_bridge_width 0.5)
			(island_removal_mode 0)
		)
		(polygon
			(pts
				(arc
					(start 125.596142 -218.692222)
					(mid 124.938282 -218.692222)
					(end 125.596142 -218.692222)
				)
			)
		)
	)
	(zone
		(layers "F.Cu" "B.Cu" "In1.Cu" "In2.Cu" "In3.Cu" "In4.Cu" "In5.Cu" "In6.Cu"
			"In7.Cu" "In8.Cu" "In9.Cu" "In10.Cu" "In11.Cu" "In12.Cu" "In13.Cu" "In14.Cu"
			"In15.Cu" "In16.Cu"
		)
		(hatch none 0.5)
		(connect_pads
			(clearance 0)
		)
		(min_thickness 0.25)
		(keepout
			(tracks not_allowed)
			(vias allowed)
			(pads allowed)
			(copperpour not_allowed)
			(footprints allowed)
		)
		(placement
			(enabled no)
			(sheetname "")
		)
		(fill
			(thermal_gap 0.5)
			(thermal_bridge_width 0.5)
			(island_removal_mode 0)
		)
		(polygon
			(pts
				(arc
					(start 261.856982 7.571994)
					(mid 262.237982 7.190994)
					(end 262.618982 7.571994)
				)
				(arc
					(start 262.618982 8.435594)
					(mid 262.237982 8.816594)
					(end 261.856982 8.435594)
				)
			)
		)
	)
	(zone
		(layers "F.Cu" "B.Cu" "In1.Cu" "In2.Cu" "In3.Cu" "In4.Cu" "In5.Cu" "In6.Cu"
			"In7.Cu" "In8.Cu" "In9.Cu" "In10.Cu" "In11.Cu" "In12.Cu" "In13.Cu" "In14.Cu"
			"In15.Cu" "In16.Cu"
		)
		(hatch none 0.5)
		(connect_pads
			(clearance 0)
		)
		(min_thickness 0.25)
		(keepout
			(tracks not_allowed)
			(vias allowed)
			(pads allowed)
			(copperpour not_allowed)
			(footprints allowed)
		)
		(placement
			(enabled no)
			(sheetname "")
		)
		(fill
			(thermal_gap 0.5)
			(thermal_bridge_width 0.5)
			(island_removal_mode 0)
		)
		(polygon
			(pts
				(arc
					(start 127.475742 -218.692222)
					(mid 126.817882 -218.692222)
					(end 127.475742 -218.692222)
				)
			)
		)
	)
	(zone
		(layers "F.Cu" "B.Cu" "In1.Cu" "In2.Cu" "In3.Cu" "In4.Cu" "In5.Cu" "In6.Cu"
			"In7.Cu" "In8.Cu" "In9.Cu" "In10.Cu" "In11.Cu" "In12.Cu" "In13.Cu" "In14.Cu"
			"In15.Cu" "In16.Cu"
		)
		(hatch none 0.5)
		(connect_pads
			(clearance 0)
		)
		(min_thickness 0.25)
		(keepout
			(tracks not_allowed)
			(vias allowed)
			(pads allowed)
			(copperpour not_allowed)
			(footprints allowed)
		)
		(placement
			(enabled no)
			(sheetname "")
		)
		(fill
			(thermal_gap 0.5)
			(thermal_bridge_width 0.5)
			(island_removal_mode 0)
		)
		(polygon
			(pts
				(arc
					(start 133.036564 -289.807142)
					(mid 133.694424 -289.807142)
					(end 133.036564 -289.807142)
				)
			)
		)
	)
	(zone
		(layers "F.Cu" "B.Cu" "In1.Cu" "In2.Cu" "In3.Cu" "In4.Cu" "In5.Cu" "In6.Cu"
			"In7.Cu" "In8.Cu" "In9.Cu" "In10.Cu" "In11.Cu" "In12.Cu" "In13.Cu" "In14.Cu"
			"In15.Cu" "In16.Cu"
		)
		(hatch none 0.5)
		(connect_pads
			(clearance 0)
		)
		(min_thickness 0.25)
		(keepout
			(tracks not_allowed)
			(vias allowed)
			(pads allowed)
			(copperpour not_allowed)
			(footprints allowed)
		)
		(placement
			(enabled no)
			(sheetname "")
		)
		(fill
			(thermal_gap 0.5)
			(thermal_bridge_width 0.5)
			(island_removal_mode 0)
		)
		(polygon
			(pts
				(arc
					(start 350.93275 -285.563056)
					(mid 350.860761 -285.490897)
					(end 350.762316 -285.464504)
				)
				(arc
					(start 350.762316 -285.464504)
					(mid 350.623122 -285.52216)
					(end 350.565466 -285.661354)
				)
				(arc
					(start 350.565466 -285.661354)
					(mid 350.572223 -285.712235)
					(end 350.591882 -285.759652)
				)
				(arc
					(start 351.061782 -286.573722)
					(mid 351.133771 -286.645881)
					(end 351.232216 -286.672274)
				)
				(arc
					(start 351.232216 -286.672274)
					(mid 351.37141 -286.614618)
					(end 351.429066 -286.475424)
				)
				(arc
					(start 351.429066 -286.475424)
					(mid 351.422309 -286.424543)
					(end 351.40265 -286.377126)
				)
			)
		)
	)
	(zone
		(layers "F.Cu" "B.Cu" "In1.Cu" "In2.Cu" "In3.Cu" "In4.Cu" "In5.Cu" "In6.Cu"
			"In7.Cu" "In8.Cu" "In9.Cu" "In10.Cu" "In11.Cu" "In12.Cu" "In13.Cu" "In14.Cu"
			"In15.Cu" "In16.Cu"
		)
		(hatch none 0.5)
		(connect_pads
			(clearance 0)
		)
		(min_thickness 0.25)
		(keepout
			(tracks not_allowed)
			(vias allowed)
			(pads allowed)
			(copperpour not_allowed)
			(footprints allowed)
		)
		(placement
			(enabled no)
			(sheetname "")
		)
		(fill
			(thermal_gap 0.5)
			(thermal_bridge_width 0.5)
			(island_removal_mode 0)
		)
		(polygon
			(pts
				(arc
					(start 98.812096 -217.878406)
					(mid 98.154236 -217.878406)
					(end 98.812096 -217.878406)
				)
			)
		)
	)
	(zone
		(layers "F.Cu" "B.Cu" "In1.Cu" "In2.Cu" "In3.Cu" "In4.Cu" "In5.Cu" "In6.Cu"
			"In7.Cu" "In8.Cu" "In9.Cu" "In10.Cu" "In11.Cu" "In12.Cu" "In13.Cu" "In14.Cu"
			"In15.Cu" "In16.Cu"
		)
		(hatch none 0.5)
		(connect_pads
			(clearance 0)
		)
		(min_thickness 0.25)
		(keepout
			(tracks not_allowed)
			(vias allowed)
			(pads allowed)
			(copperpour not_allowed)
			(footprints allowed)
		)
		(placement
			(enabled no)
			(sheetname "")
		)
		(fill
			(thermal_gap 0.5)
			(thermal_bridge_width 0.5)
			(island_removal_mode 0)
		)
		(polygon
			(pts
				(arc
					(start 350.621346 -281.59202)
					(mid 349.963486 -281.59202)
					(end 350.621346 -281.59202)
				)
			)
		)
	)
	(zone
		(layers "F.Cu" "B.Cu" "In1.Cu" "In2.Cu" "In3.Cu" "In4.Cu" "In5.Cu" "In6.Cu"
			"In7.Cu" "In8.Cu" "In9.Cu" "In10.Cu" "In11.Cu" "In12.Cu" "In13.Cu" "In14.Cu"
			"In15.Cu" "In16.Cu"
		)
		(hatch none 0.5)
		(connect_pads
			(clearance 0)
		)
		(min_thickness 0.25)
		(keepout
			(tracks not_allowed)
			(vias allowed)
			(pads allowed)
			(copperpour not_allowed)
			(footprints allowed)
		)
		(placement
			(enabled no)
			(sheetname "")
		)
		(fill
			(thermal_gap 0.5)
			(thermal_bridge_width 0.5)
			(island_removal_mode 0)
		)
		(polygon
			(pts
				(arc
					(start 313.169808 -403.502876)
					(mid 312.788808 -403.883876)
					(end 313.169808 -404.264876)
				)
				(arc
					(start 314.033408 -404.264876)
					(mid 314.414408 -403.883876)
					(end 314.033408 -403.502876)
				)
			)
		)
	)
	(zone
		(layers "F.Cu" "B.Cu" "In1.Cu" "In2.Cu" "In3.Cu" "In4.Cu" "In5.Cu" "In6.Cu"
			"In7.Cu" "In8.Cu" "In9.Cu" "In10.Cu" "In11.Cu" "In12.Cu" "In13.Cu" "In14.Cu"
			"In15.Cu" "In16.Cu"
		)
		(hatch none 0.5)
		(connect_pads
			(clearance 0)
		)
		(min_thickness 0.25)
		(keepout
			(tracks not_allowed)
			(vias allowed)
			(pads allowed)
			(copperpour not_allowed)
			(footprints allowed)
		)
		(placement
			(enabled no)
			(sheetname "")
		)
		(fill
			(thermal_gap 0.5)
			(thermal_bridge_width 0.5)
			(island_removal_mode 0)
		)
		(polygon
			(pts
				(arc
					(start 373.53621 -221.94774)
					(mid 372.87835 -221.94774)
					(end 373.53621 -221.94774)
				)
			)
		)
	)
	(zone
		(layers "F.Cu" "B.Cu" "In1.Cu" "In2.Cu" "In3.Cu" "In4.Cu" "In5.Cu" "In6.Cu"
			"In7.Cu" "In8.Cu" "In9.Cu" "In10.Cu" "In11.Cu" "In12.Cu" "In13.Cu" "In14.Cu"
			"In15.Cu" "In16.Cu"
		)
		(hatch none 0.5)
		(connect_pads
			(clearance 0)
		)
		(min_thickness 0.25)
		(keepout
			(tracks not_allowed)
			(vias allowed)
			(pads allowed)
			(copperpour not_allowed)
			(footprints allowed)
		)
		(placement
			(enabled no)
			(sheetname "")
		)
		(fill
			(thermal_gap 0.5)
			(thermal_bridge_width 0.5)
			(island_removal_mode 0)
		)
		(polygon
			(pts
				(arc
					(start 358.720136 -43.229784)
					(mid 358.339136 -43.610784)
					(end 358.720136 -43.991784)
				)
				(arc
					(start 359.583736 -43.991784)
					(mid 359.964736 -43.610784)
					(end 359.583736 -43.229784)
				)
			)
		)
	)
	(zone
		(layers "F.Cu" "B.Cu" "In1.Cu" "In2.Cu" "In3.Cu" "In4.Cu" "In5.Cu" "In6.Cu"
			"In7.Cu" "In8.Cu" "In9.Cu" "In10.Cu" "In11.Cu" "In12.Cu" "In13.Cu" "In14.Cu"
			"In15.Cu" "In16.Cu"
		)
		(hatch none 0.5)
		(connect_pads
			(clearance 0)
		)
		(min_thickness 0.25)
		(keepout
			(tracks not_allowed)
			(vias allowed)
			(pads allowed)
			(copperpour not_allowed)
			(footprints allowed)
		)
		(placement
			(enabled no)
			(sheetname "")
		)
		(fill
			(thermal_gap 0.5)
			(thermal_bridge_width 0.5)
			(island_removal_mode 0)
		)
		(polygon
			(pts
				(arc
					(start 37.830252 -385.793996)
					(mid 38.211252 -385.412996)
					(end 37.830252 -385.031996)
				)
				(arc
					(start 36.966652 -385.031996)
					(mid 36.585652 -385.412996)
					(end 36.966652 -385.793996)
				)
			)
		)
	)
	(zone
		(layers "F.Cu" "B.Cu" "In1.Cu" "In2.Cu" "In3.Cu" "In4.Cu" "In5.Cu" "In6.Cu"
			"In7.Cu" "In8.Cu" "In9.Cu" "In10.Cu" "In11.Cu" "In12.Cu" "In13.Cu" "In14.Cu"
			"In15.Cu" "In16.Cu"
		)
		(hatch none 0.5)
		(connect_pads
			(clearance 0)
		)
		(min_thickness 0.25)
		(keepout
			(tracks not_allowed)
			(vias allowed)
			(pads allowed)
			(copperpour not_allowed)
			(footprints allowed)
		)
		(placement
			(enabled no)
			(sheetname "")
		)
		(fill
			(thermal_gap 0.5)
			(thermal_bridge_width 0.5)
			(island_removal_mode 0)
		)
		(polygon
			(pts
				(arc
					(start 121.367296 -217.878406)
					(mid 120.709436 -217.878406)
					(end 121.367296 -217.878406)
				)
			)
		)
	)
	(zone
		(layers "F.Cu" "B.Cu" "In1.Cu" "In2.Cu" "In3.Cu" "In4.Cu" "In5.Cu" "In6.Cu"
			"In7.Cu" "In8.Cu" "In9.Cu" "In10.Cu" "In11.Cu" "In12.Cu" "In13.Cu" "In14.Cu"
			"In15.Cu" "In16.Cu"
		)
		(hatch none 0.5)
		(connect_pads
			(clearance 0)
		)
		(min_thickness 0.25)
		(keepout
			(tracks not_allowed)
			(vias allowed)
			(pads allowed)
			(copperpour not_allowed)
			(footprints allowed)
		)
		(placement
			(enabled no)
			(sheetname "")
		)
		(fill
			(thermal_gap 0.5)
			(thermal_bridge_width 0.5)
			(island_removal_mode 0)
		)
		(polygon
			(pts
				(arc
					(start 371.42293 -403.502876)
					(mid 371.04193 -403.883876)
					(end 371.42293 -404.264876)
				)
				(arc
					(start 372.28653 -404.264876)
					(mid 372.66753 -403.883876)
					(end 372.28653 -403.502876)
				)
			)
		)
	)
	(zone
		(layers "F.Cu" "B.Cu" "In1.Cu" "In2.Cu" "In3.Cu" "In4.Cu" "In5.Cu" "In6.Cu"
			"In7.Cu" "In8.Cu" "In9.Cu" "In10.Cu" "In11.Cu" "In12.Cu" "In13.Cu" "In14.Cu"
			"In15.Cu" "In16.Cu"
		)
		(hatch none 0.5)
		(connect_pads
			(clearance 0)
		)
		(min_thickness 0.25)
		(keepout
			(tracks not_allowed)
			(vias allowed)
			(pads allowed)
			(copperpour not_allowed)
			(footprints allowed)
		)
		(placement
			(enabled no)
			(sheetname "")
		)
		(fill
			(thermal_gap 0.5)
			(thermal_bridge_width 0.5)
			(island_removal_mode 0)
		)
		(polygon
			(pts
				(arc
					(start 146.007074 -409.649168)
					(mid 145.626074 -410.030168)
					(end 146.007074 -410.411168)
				)
				(arc
					(start 146.870674 -410.411168)
					(mid 147.251674 -410.030168)
					(end 146.870674 -409.649168)
				)
			)
		)
	)
	(zone
		(layers "F.Cu" "B.Cu" "In1.Cu" "In2.Cu" "In3.Cu" "In4.Cu" "In5.Cu" "In6.Cu"
			"In7.Cu" "In8.Cu" "In9.Cu" "In10.Cu" "In11.Cu" "In12.Cu" "In13.Cu" "In14.Cu"
			"In15.Cu" "In16.Cu"
		)
		(hatch none 0.5)
		(connect_pads
			(clearance 0)
		)
		(min_thickness 0.25)
		(keepout
			(tracks not_allowed)
			(vias allowed)
			(pads allowed)
			(copperpour not_allowed)
			(footprints allowed)
		)
		(placement
			(enabled no)
			(sheetname "")
		)
		(fill
			(thermal_gap 0.5)
			(thermal_bridge_width 0.5)
			(island_removal_mode 0)
		)
		(polygon
			(pts
				(arc
					(start 129.637282 -220.319854)
					(mid 130.295142 -220.319854)
					(end 129.637282 -220.319854)
				)
			)
		)
	)
	(zone
		(layers "F.Cu" "B.Cu" "In1.Cu" "In2.Cu" "In3.Cu" "In4.Cu" "In5.Cu" "In6.Cu"
			"In7.Cu" "In8.Cu" "In9.Cu" "In10.Cu" "In11.Cu" "In12.Cu" "In13.Cu" "In14.Cu"
			"In15.Cu" "In16.Cu"
		)
		(hatch none 0.5)
		(connect_pads
			(clearance 0)
		)
		(min_thickness 0.25)
		(keepout
			(tracks not_allowed)
			(vias allowed)
			(pads allowed)
			(copperpour not_allowed)
			(footprints allowed)
		)
		(placement
			(enabled no)
			(sheetname "")
		)
		(fill
			(thermal_gap 0.5)
			(thermal_bridge_width 0.5)
			(island_removal_mode 0)
		)
		(polygon
			(pts
				(arc
					(start 122.728228 -285.759652)
					(mid 122.747912 -285.712242)
					(end 122.754644 -285.661354)
				)
				(arc
					(start 122.754644 -285.661354)
					(mid 122.696988 -285.52216)
					(end 122.557794 -285.464504)
				)
				(arc
					(start 122.557794 -285.464504)
					(mid 122.459363 -285.49092)
					(end 122.38736 -285.563056)
				)
				(arc
					(start 121.917714 -286.377126)
					(mid 121.89803 -286.424536)
					(end 121.891298 -286.475424)
				)
				(arc
					(start 121.891298 -286.475424)
					(mid 121.948954 -286.614618)
					(end 122.088148 -286.672274)
				)
				(arc
					(start 122.088148 -286.672274)
					(mid 122.186579 -286.645858)
					(end 122.258582 -286.573722)
				)
			)
		)
	)
	(zone
		(layers "F.Cu" "B.Cu" "In1.Cu" "In2.Cu" "In3.Cu" "In4.Cu" "In5.Cu" "In6.Cu"
			"In7.Cu" "In8.Cu" "In9.Cu" "In10.Cu" "In11.Cu" "In12.Cu" "In13.Cu" "In14.Cu"
			"In15.Cu" "In16.Cu"
		)
		(hatch none 0.5)
		(connect_pads
			(clearance 0)
		)
		(min_thickness 0.25)
		(keepout
			(tracks not_allowed)
			(vias allowed)
			(pads allowed)
			(copperpour not_allowed)
			(footprints allowed)
		)
		(placement
			(enabled no)
			(sheetname "")
		)
		(fill
			(thermal_gap 0.5)
			(thermal_bridge_width 0.5)
			(island_removal_mode 0)
		)
		(polygon
			(pts
				(arc
					(start 353.634548 -213.646766)
					(mid 353.56684 -213.574915)
					(end 353.471734 -213.548468)
				)
				(arc
					(start 353.471734 -213.548468)
					(mid 353.34152 -213.602404)
					(end 353.287584 -213.732618)
				)
				(arc
					(start 353.287584 -213.732618)
					(mid 353.293035 -213.776839)
					(end 353.30892 -213.81847)
				)
				(arc
					(start 353.778312 -214.708486)
					(mid 353.84602 -214.780337)
					(end 353.941126 -214.806784)
				)
				(arc
					(start 353.941126 -214.806784)
					(mid 354.07134 -214.752848)
					(end 354.125276 -214.622634)
				)
				(arc
					(start 354.125276 -214.622634)
					(mid 354.119825 -214.578413)
					(end 354.10394 -214.536782)
				)
			)
		)
	)
	(zone
		(layers "F.Cu" "B.Cu" "In1.Cu" "In2.Cu" "In3.Cu" "In4.Cu" "In5.Cu" "In6.Cu"
			"In7.Cu" "In8.Cu" "In9.Cu" "In10.Cu" "In11.Cu" "In12.Cu" "In13.Cu" "In14.Cu"
			"In15.Cu" "In16.Cu"
		)
		(hatch none 0.5)
		(connect_pads
			(clearance 0)
		)
		(min_thickness 0.25)
		(keepout
			(tracks not_allowed)
			(vias allowed)
			(pads allowed)
			(copperpour not_allowed)
			(footprints allowed)
		)
		(placement
			(enabled no)
			(sheetname "")
		)
		(fill
			(thermal_gap 0.5)
			(thermal_bridge_width 0.5)
			(island_removal_mode 0)
		)
		(polygon
			(pts
				(arc
					(start 128.885696 -224.389442)
					(mid 128.227836 -224.389442)
					(end 128.885696 -224.389442)
				)
			)
		)
	)
	(zone
		(layers "F.Cu" "B.Cu" "In1.Cu" "In2.Cu" "In3.Cu" "In4.Cu" "In5.Cu" "In6.Cu"
			"In7.Cu" "In8.Cu" "In9.Cu" "In10.Cu" "In11.Cu" "In12.Cu" "In13.Cu" "In14.Cu"
			"In15.Cu" "In16.Cu"
		)
		(hatch none 0.5)
		(connect_pads
			(clearance 0)
		)
		(min_thickness 0.25)
		(keepout
			(tracks not_allowed)
			(vias allowed)
			(pads allowed)
			(copperpour not_allowed)
			(footprints allowed)
		)
		(placement
			(enabled no)
			(sheetname "")
		)
		(fill
			(thermal_gap 0.5)
			(thermal_bridge_width 0.5)
			(island_removal_mode 0)
		)
		(polygon
			(pts
				(arc
					(start 357.871268 -224.291144)
					(mid 357.799279 -224.218985)
					(end 357.700834 -224.192592)
				)
				(arc
					(start 357.700834 -224.192592)
					(mid 357.56164 -224.250248)
					(end 357.503984 -224.389442)
				)
				(arc
					(start 357.503984 -224.389442)
					(mid 357.510741 -224.440323)
					(end 357.5304 -224.48774)
				)
				(arc
					(start 358.000046 -225.301556)
					(mid 358.072035 -225.373715)
					(end 358.17048 -225.400108)
				)
				(arc
					(start 358.17048 -225.400108)
					(mid 358.309674 -225.342452)
					(end 358.36733 -225.203258)
				)
				(arc
					(start 358.36733 -225.203258)
					(mid 358.360573 -225.152377)
					(end 358.340914 -225.10496)
				)
			)
		)
	)
	(zone
		(layers "F.Cu" "B.Cu" "In1.Cu" "In2.Cu" "In3.Cu" "In4.Cu" "In5.Cu" "In6.Cu"
			"In7.Cu" "In8.Cu" "In9.Cu" "In10.Cu" "In11.Cu" "In12.Cu" "In13.Cu" "In14.Cu"
			"In15.Cu" "In16.Cu"
		)
		(hatch none 0.5)
		(connect_pads
			(clearance 0)
		)
		(min_thickness 0.25)
		(keepout
			(tracks not_allowed)
			(vias allowed)
			(pads allowed)
			(copperpour not_allowed)
			(footprints allowed)
		)
		(placement
			(enabled no)
			(sheetname "")
		)
		(fill
			(thermal_gap 0.5)
			(thermal_bridge_width 0.5)
			(island_removal_mode 0)
		)
		(polygon
			(pts
				(arc
					(start 347.691964 -221.133924)
					(mid 347.034104 -221.133924)
					(end 347.691964 -221.133924)
				)
			)
		)
	)
	(zone
		(layers "F.Cu" "B.Cu" "In1.Cu" "In2.Cu" "In3.Cu" "In4.Cu" "In5.Cu" "In6.Cu"
			"In7.Cu" "In8.Cu" "In9.Cu" "In10.Cu" "In11.Cu" "In12.Cu" "In13.Cu" "In14.Cu"
			"In15.Cu" "In16.Cu"
		)
		(hatch none 0.5)
		(connect_pads
			(clearance 0)
		)
		(min_thickness 0.25)
		(keepout
			(tracks not_allowed)
			(vias allowed)
			(pads allowed)
			(copperpour not_allowed)
			(footprints allowed)
		)
		(placement
			(enabled no)
			(sheetname "")
		)
		(fill
			(thermal_gap 0.5)
			(thermal_bridge_width 0.5)
			(island_removal_mode 0)
		)
		(polygon
			(pts
				(arc
					(start 357.55961 -217.064336)
					(mid 356.90175 -217.064336)
					(end 357.55961 -217.064336)
				)
			)
		)
	)
	(zone
		(layers "F.Cu" "B.Cu" "In1.Cu" "In2.Cu" "In3.Cu" "In4.Cu" "In5.Cu" "In6.Cu"
			"In7.Cu" "In8.Cu" "In9.Cu" "In10.Cu" "In11.Cu" "In12.Cu" "In13.Cu" "In14.Cu"
			"In15.Cu" "In16.Cu"
		)
		(hatch none 0.5)
		(connect_pads
			(clearance 0)
		)
		(min_thickness 0.25)
		(keepout
			(tracks not_allowed)
			(vias allowed)
			(pads allowed)
			(copperpour not_allowed)
			(footprints allowed)
		)
		(placement
			(enabled no)
			(sheetname "")
		)
		(fill
			(thermal_gap 0.5)
			(thermal_bridge_width 0.5)
			(island_removal_mode 0)
		)
		(polygon
			(pts
				(arc
					(start 120.427496 -224.389442)
					(mid 119.769636 -224.389442)
					(end 120.427496 -224.389442)
				)
			)
		)
	)
	(zone
		(layers "F.Cu" "B.Cu" "In1.Cu" "In2.Cu" "In3.Cu" "In4.Cu" "In5.Cu" "In6.Cu"
			"In7.Cu" "In8.Cu" "In9.Cu" "In10.Cu" "In11.Cu" "In12.Cu" "In13.Cu" "In14.Cu"
			"In15.Cu" "In16.Cu"
		)
		(hatch none 0.5)
		(connect_pads
			(clearance 0)
		)
		(min_thickness 0.25)
		(keepout
			(tracks not_allowed)
			(vias allowed)
			(pads allowed)
			(copperpour not_allowed)
			(footprints allowed)
		)
		(placement
			(enabled no)
			(sheetname "")
		)
		(fill
			(thermal_gap 0.5)
			(thermal_bridge_width 0.5)
			(island_removal_mode 0)
		)
		(polygon
			(pts
				(arc
					(start 67.705478 -409.649168)
					(mid 67.324478 -410.030168)
					(end 67.705478 -410.411168)
				)
				(arc
					(start 68.569078 -410.411168)
					(mid 68.950078 -410.030168)
					(end 68.569078 -409.649168)
				)
			)
		)
	)
	(zone
		(layers "F.Cu" "B.Cu" "In1.Cu" "In2.Cu" "In3.Cu" "In4.Cu" "In5.Cu" "In6.Cu"
			"In7.Cu" "In8.Cu" "In9.Cu" "In10.Cu" "In11.Cu" "In12.Cu" "In13.Cu" "In14.Cu"
			"In15.Cu" "In16.Cu"
		)
		(hatch none 0.5)
		(connect_pads
			(clearance 0)
		)
		(min_thickness 0.25)
		(keepout
			(tracks not_allowed)
			(vias allowed)
			(pads allowed)
			(copperpour not_allowed)
			(footprints allowed)
		)
		(placement
			(enabled no)
			(sheetname "")
		)
		(fill
			(thermal_gap 0.5)
			(thermal_bridge_width 0.5)
			(island_removal_mode 0)
		)
		(polygon
			(pts
				(arc
					(start 335.584292 -284.847538)
					(mid 334.926432 -284.847538)
					(end 335.584292 -284.847538)
				)
			)
		)
	)
	(zone
		(layers "F.Cu" "B.Cu" "In1.Cu" "In2.Cu" "In3.Cu" "In4.Cu" "In5.Cu" "In6.Cu"
			"In7.Cu" "In8.Cu" "In9.Cu" "In10.Cu" "In11.Cu" "In12.Cu" "In13.Cu" "In14.Cu"
			"In15.Cu" "In16.Cu"
		)
		(hatch none 0.5)
		(connect_pads
			(clearance 0)
		)
		(min_thickness 0.25)
		(keepout
			(tracks not_allowed)
			(vias allowed)
			(pads allowed)
			(copperpour not_allowed)
			(footprints allowed)
		)
		(placement
			(enabled no)
			(sheetname "")
		)
		(fill
			(thermal_gap 0.5)
			(thermal_bridge_width 0.5)
			(island_removal_mode 0)
		)
		(polygon
			(pts
				(arc
					(start 104.842818 -275.08073)
					(mid 105.500678 -275.08073)
					(end 104.842818 -275.08073)
				)
			)
		)
	)
	(zone
		(layers "F.Cu" "B.Cu" "In1.Cu" "In2.Cu" "In3.Cu" "In4.Cu" "In5.Cu" "In6.Cu"
			"In7.Cu" "In8.Cu" "In9.Cu" "In10.Cu" "In11.Cu" "In12.Cu" "In13.Cu" "In14.Cu"
			"In15.Cu" "In16.Cu"
		)
		(hatch none 0.5)
		(connect_pads
			(clearance 0)
		)
		(min_thickness 0.25)
		(keepout
			(tracks not_allowed)
			(vias allowed)
			(pads allowed)
			(copperpour not_allowed)
			(footprints allowed)
		)
		(placement
			(enabled no)
			(sheetname "")
		)
		(fill
			(thermal_gap 0.5)
			(thermal_bridge_width 0.5)
			(island_removal_mode 0)
		)
		(polygon
			(pts
				(arc
					(start 53.736748 -6.343396)
					(mid 53.355748 -6.724396)
					(end 53.736748 -7.105396)
				)
				(arc
					(start 54.600348 -7.105396)
					(mid 54.981348 -6.724396)
					(end 54.600348 -6.343396)
				)
			)
		)
	)
	(zone
		(layers "F.Cu" "B.Cu" "In1.Cu" "In2.Cu" "In3.Cu" "In4.Cu" "In5.Cu" "In6.Cu"
			"In7.Cu" "In8.Cu" "In9.Cu" "In10.Cu" "In11.Cu" "In12.Cu" "In13.Cu" "In14.Cu"
			"In15.Cu" "In16.Cu"
		)
		(hatch none 0.5)
		(connect_pads
			(clearance 0)
		)
		(min_thickness 0.25)
		(keepout
			(tracks not_allowed)
			(vias allowed)
			(pads allowed)
			(copperpour not_allowed)
			(footprints allowed)
		)
		(placement
			(enabled no)
			(sheetname "")
		)
		(fill
			(thermal_gap 0.5)
			(thermal_bridge_width 0.5)
			(island_removal_mode 0)
		)
		(polygon
			(pts
				(arc
					(start 355.940614 -44.617386)
					(mid 355.559614 -44.998386)
					(end 355.940614 -45.379386)
				)
				(arc
					(start 356.804214 -45.379386)
					(mid 357.185214 -44.998386)
					(end 356.804214 -44.617386)
				)
			)
		)
	)
	(zone
		(layers "F.Cu" "B.Cu" "In1.Cu" "In2.Cu" "In3.Cu" "In4.Cu" "In5.Cu" "In6.Cu"
			"In7.Cu" "In8.Cu" "In9.Cu" "In10.Cu" "In11.Cu" "In12.Cu" "In13.Cu" "In14.Cu"
			"In15.Cu" "In16.Cu"
		)
		(hatch none 0.5)
		(connect_pads
			(clearance 0)
		)
		(min_thickness 0.25)
		(keepout
			(tracks not_allowed)
			(vias allowed)
			(pads allowed)
			(copperpour not_allowed)
			(footprints allowed)
		)
		(placement
			(enabled no)
			(sheetname "")
		)
		(fill
			(thermal_gap 0.5)
			(thermal_bridge_width 0.5)
			(island_removal_mode 0)
		)
		(polygon
			(pts
				(arc
					(start 106.800142 -221.94774)
					(mid 106.142282 -221.94774)
					(end 106.800142 -221.94774)
				)
			)
		)
	)
	(zone
		(layers "F.Cu" "B.Cu" "In1.Cu" "In2.Cu" "In3.Cu" "In4.Cu" "In5.Cu" "In6.Cu"
			"In7.Cu" "In8.Cu" "In9.Cu" "In10.Cu" "In11.Cu" "In12.Cu" "In13.Cu" "In14.Cu"
			"In15.Cu" "In16.Cu"
		)
		(hatch none 0.5)
		(connect_pads
			(clearance 0)
		)
		(min_thickness 0.25)
		(keepout
			(tracks not_allowed)
			(vias allowed)
			(pads allowed)
			(copperpour not_allowed)
			(footprints allowed)
		)
		(placement
			(enabled no)
			(sheetname "")
		)
		(fill
			(thermal_gap 0.5)
			(thermal_bridge_width 0.5)
			(island_removal_mode 0)
		)
		(polygon
			(pts
				(arc
					(start 338.76361 -220.319854)
					(mid 338.10575 -220.319854)
					(end 338.76361 -220.319854)
				)
			)
		)
	)
	(zone
		(layers "F.Cu" "B.Cu" "In1.Cu" "In2.Cu" "In3.Cu" "In4.Cu" "In5.Cu" "In6.Cu"
			"In7.Cu" "In8.Cu" "In9.Cu" "In10.Cu" "In11.Cu" "In12.Cu" "In13.Cu" "In14.Cu"
			"In15.Cu" "In16.Cu"
		)
		(hatch none 0.5)
		(connect_pads
			(clearance 0)
		)
		(min_thickness 0.25)
		(keepout
			(tracks not_allowed)
			(vias allowed)
			(pads allowed)
			(copperpour not_allowed)
			(footprints allowed)
		)
		(placement
			(enabled no)
			(sheetname "")
		)
		(fill
			(thermal_gap 0.5)
			(thermal_bridge_width 0.5)
			(island_removal_mode 0)
		)
		(polygon
			(pts
				(arc
					(start 346.28201 -220.319854)
					(mid 345.62415 -220.319854)
					(end 346.28201 -220.319854)
				)
			)
		)
	)
	(zone
		(layers "F.Cu" "B.Cu" "In1.Cu" "In2.Cu" "In3.Cu" "In4.Cu" "In5.Cu" "In6.Cu"
			"In7.Cu" "In8.Cu" "In9.Cu" "In10.Cu" "In11.Cu" "In12.Cu" "In13.Cu" "In14.Cu"
			"In15.Cu" "In16.Cu"
		)
		(hatch none 0.5)
		(connect_pads
			(clearance 0)
		)
		(min_thickness 0.25)
		(keepout
			(tracks not_allowed)
			(vias allowed)
			(pads allowed)
			(copperpour not_allowed)
			(footprints allowed)
		)
		(placement
			(enabled no)
			(sheetname "")
		)
		(fill
			(thermal_gap 0.5)
			(thermal_bridge_width 0.5)
			(island_removal_mode 0)
		)
		(polygon
			(pts
				(arc
					(start 90.865198 -400.477228)
					(mid 90.484198 -400.858228)
					(end 90.865198 -401.239228)
				)
				(arc
					(start 91.728798 -401.239228)
					(mid 92.109798 -400.858228)
					(end 91.728798 -400.477228)
				)
			)
		)
	)
	(zone
		(layers "F.Cu" "B.Cu" "In1.Cu" "In2.Cu" "In3.Cu" "In4.Cu" "In5.Cu" "In6.Cu"
			"In7.Cu" "In8.Cu" "In9.Cu" "In10.Cu" "In11.Cu" "In12.Cu" "In13.Cu" "In14.Cu"
			"In15.Cu" "In16.Cu"
		)
		(hatch none 0.5)
		(connect_pads
			(clearance 0)
		)
		(min_thickness 0.25)
		(keepout
			(tracks not_allowed)
			(vias allowed)
			(pads allowed)
			(copperpour not_allowed)
			(footprints allowed)
		)
		(placement
			(enabled no)
			(sheetname "")
		)
		(fill
			(thermal_gap 0.5)
			(thermal_bridge_width 0.5)
			(island_removal_mode 0)
		)
		(polygon
			(pts
				(arc
					(start 120.897142 -223.575626)
					(mid 120.239282 -223.575626)
					(end 120.897142 -223.575626)
				)
			)
		)
	)
	(zone
		(layers "F.Cu" "B.Cu" "In1.Cu" "In2.Cu" "In3.Cu" "In4.Cu" "In5.Cu" "In6.Cu"
			"In7.Cu" "In8.Cu" "In9.Cu" "In10.Cu" "In11.Cu" "In12.Cu" "In13.Cu" "In14.Cu"
			"In15.Cu" "In16.Cu"
		)
		(hatch none 0.5)
		(connect_pads
			(clearance 0)
		)
		(min_thickness 0.25)
		(keepout
			(tracks not_allowed)
			(vias allowed)
			(pads allowed)
			(copperpour not_allowed)
			(footprints allowed)
		)
		(placement
			(enabled no)
			(sheetname "")
		)
		(fill
			(thermal_gap 0.5)
			(thermal_bridge_width 0.5)
			(island_removal_mode 0)
		)
		(polygon
			(pts
				(arc
					(start 320.642488 -409.649168)
					(mid 320.261488 -410.030168)
					(end 320.642488 -410.411168)
				)
				(arc
					(start 321.506088 -410.411168)
					(mid 321.887088 -410.030168)
					(end 321.506088 -409.649168)
				)
			)
		)
	)
	(zone
		(layers "F.Cu" "B.Cu" "In1.Cu" "In2.Cu" "In3.Cu" "In4.Cu" "In5.Cu" "In6.Cu"
			"In7.Cu" "In8.Cu" "In9.Cu" "In10.Cu" "In11.Cu" "In12.Cu" "In13.Cu" "In14.Cu"
			"In15.Cu" "In16.Cu"
		)
		(hatch none 0.5)
		(connect_pads
			(clearance 0)
		)
		(min_thickness 0.25)
		(keepout
			(tracks not_allowed)
			(vias allowed)
			(pads allowed)
			(copperpour not_allowed)
			(footprints allowed)
		)
		(placement
			(enabled no)
			(sheetname "")
		)
		(fill
			(thermal_gap 0.5)
			(thermal_bridge_width 0.5)
			(island_removal_mode 0)
		)
		(polygon
			(pts
				(arc
					(start 119.439182 -284.74924)
					(mid 119.367193 -284.677081)
					(end 119.268748 -284.650688)
				)
				(arc
					(start 119.268748 -284.650688)
					(mid 119.129554 -284.708344)
					(end 119.071898 -284.847538)
				)
				(arc
					(start 119.071898 -284.847538)
					(mid 119.078655 -284.898419)
					(end 119.098314 -284.945836)
				)
				(arc
					(start 119.56796 -285.759652)
					(mid 119.639949 -285.831811)
					(end 119.738394 -285.858204)
				)
				(arc
					(start 119.738394 -285.858204)
					(mid 119.877588 -285.800548)
					(end 119.935244 -285.661354)
				)
				(arc
					(start 119.935244 -285.661354)
					(mid 119.928487 -285.610473)
					(end 119.908828 -285.563056)
				)
			)
		)
	)
	(zone
		(layers "F.Cu" "B.Cu" "In1.Cu" "In2.Cu" "In3.Cu" "In4.Cu" "In5.Cu" "In6.Cu"
			"In7.Cu" "In8.Cu" "In9.Cu" "In10.Cu" "In11.Cu" "In12.Cu" "In13.Cu" "In14.Cu"
			"In15.Cu" "In16.Cu"
		)
		(hatch none 0.5)
		(connect_pads
			(clearance 0)
		)
		(min_thickness 0.25)
		(keepout
			(tracks not_allowed)
			(vias allowed)
			(pads allowed)
			(copperpour not_allowed)
			(footprints allowed)
		)
		(placement
			(enabled no)
			(sheetname "")
		)
		(fill
			(thermal_gap 0.5)
			(thermal_bridge_width 0.5)
			(island_removal_mode 0)
		)
		(polygon
			(pts
				(arc
					(start 103.040942 -218.692222)
					(mid 102.383082 -218.692222)
					(end 103.040942 -218.692222)
				)
			)
		)
	)
	(zone
		(layers "F.Cu" "B.Cu" "In1.Cu" "In2.Cu" "In3.Cu" "In4.Cu" "In5.Cu" "In6.Cu"
			"In7.Cu" "In8.Cu" "In9.Cu" "In10.Cu" "In11.Cu" "In12.Cu" "In13.Cu" "In14.Cu"
			"In15.Cu" "In16.Cu"
		)
		(hatch none 0.5)
		(connect_pads
			(clearance 0)
		)
		(min_thickness 0.25)
		(keepout
			(tracks not_allowed)
			(vias allowed)
			(pads allowed)
			(copperpour not_allowed)
			(footprints allowed)
		)
		(placement
			(enabled no)
			(sheetname "")
		)
		(fill
			(thermal_gap 0.5)
			(thermal_bridge_width 0.5)
			(island_removal_mode 0)
		)
		(polygon
			(pts
				(arc
					(start 239.4077 -134.328408)
					(mid 239.0267 -133.947408)
					(end 238.6457 -134.328408)
				)
				(arc
					(start 238.6457 -135.192008)
					(mid 239.0267 -135.573008)
					(end 239.4077 -135.192008)
				)
			)
		)
	)
	(zone
		(layers "F.Cu" "B.Cu" "In1.Cu" "In2.Cu" "In3.Cu" "In4.Cu" "In5.Cu" "In6.Cu"
			"In7.Cu" "In8.Cu" "In9.Cu" "In10.Cu" "In11.Cu" "In12.Cu" "In13.Cu" "In14.Cu"
			"In15.Cu" "In16.Cu"
		)
		(hatch none 0.5)
		(connect_pads
			(clearance 0)
		)
		(min_thickness 0.25)
		(keepout
			(tracks not_allowed)
			(vias allowed)
			(pads allowed)
			(copperpour not_allowed)
			(footprints allowed)
		)
		(placement
			(enabled no)
			(sheetname "")
		)
		(fill
			(thermal_gap 0.5)
			(thermal_bridge_width 0.5)
			(island_removal_mode 0)
		)
		(polygon
			(pts
				(arc
					(start 119.017796 -213.732618)
					(mid 118.359936 -213.732618)
					(end 119.017796 -213.732618)
				)
			)
		)
	)
	(zone
		(layers "F.Cu" "B.Cu" "In1.Cu" "In2.Cu" "In3.Cu" "In4.Cu" "In5.Cu" "In6.Cu"
			"In7.Cu" "In8.Cu" "In9.Cu" "In10.Cu" "In11.Cu" "In12.Cu" "In13.Cu" "In14.Cu"
			"In15.Cu" "In16.Cu"
		)
		(hatch none 0.5)
		(connect_pads
			(clearance 0)
		)
		(min_thickness 0.25)
		(keepout
			(tracks not_allowed)
			(vias allowed)
			(pads allowed)
			(copperpour not_allowed)
			(footprints allowed)
		)
		(placement
			(enabled no)
			(sheetname "")
		)
		(fill
			(thermal_gap 0.5)
			(thermal_bridge_width 0.5)
			(island_removal_mode 0)
		)
		(polygon
			(pts
				(arc
					(start 341.223346 -284.847538)
					(mid 340.565486 -284.847538)
					(end 341.223346 -284.847538)
				)
			)
		)
	)
	(zone
		(layers "F.Cu" "B.Cu" "In1.Cu" "In2.Cu" "In3.Cu" "In4.Cu" "In5.Cu" "In6.Cu"
			"In7.Cu" "In8.Cu" "In9.Cu" "In10.Cu" "In11.Cu" "In12.Cu" "In13.Cu" "In14.Cu"
			"In15.Cu" "In16.Cu"
		)
		(hatch none 0.5)
		(connect_pads
			(clearance 0)
		)
		(min_thickness 0.25)
		(keepout
			(tracks not_allowed)
			(vias allowed)
			(pads allowed)
			(copperpour not_allowed)
			(footprints allowed)
		)
		(placement
			(enabled no)
			(sheetname "")
		)
		(fill
			(thermal_gap 0.5)
			(thermal_bridge_width 0.5)
			(island_removal_mode 0)
		)
		(polygon
			(pts
				(arc
					(start 96.931988 -214.622634)
					(mid 96.274128 -214.622634)
					(end 96.931988 -214.622634)
				)
			)
		)
	)
	(zone
		(layers "F.Cu" "B.Cu" "In1.Cu" "In2.Cu" "In3.Cu" "In4.Cu" "In5.Cu" "In6.Cu"
			"In7.Cu" "In8.Cu" "In9.Cu" "In10.Cu" "In11.Cu" "In12.Cu" "In13.Cu" "In14.Cu"
			"In15.Cu" "In16.Cu"
		)
		(hatch none 0.5)
		(connect_pads
			(clearance 0)
		)
		(min_thickness 0.25)
		(keepout
			(tracks not_allowed)
			(vias allowed)
			(pads allowed)
			(copperpour not_allowed)
			(footprints allowed)
		)
		(placement
			(enabled no)
			(sheetname "")
		)
		(fill
			(thermal_gap 0.5)
			(thermal_bridge_width 0.5)
			(island_removal_mode 0)
		)
		(polygon
			(pts
				(arc
					(start 122.618246 -223.67367)
					(mid 122.63793 -223.62626)
					(end 122.644662 -223.575372)
				)
				(arc
					(start 122.644662 -223.575372)
					(mid 122.587006 -223.436178)
					(end 122.447812 -223.378522)
				)
				(arc
					(start 122.447812 -223.378522)
					(mid 122.349381 -223.404938)
					(end 122.277378 -223.477074)
				)
				(arc
					(start 121.807732 -224.291144)
					(mid 121.788048 -224.338554)
					(end 121.781316 -224.389442)
				)
				(arc
					(start 121.781316 -224.389442)
					(mid 121.838972 -224.528636)
					(end 121.978166 -224.586292)
				)
				(arc
					(start 121.978166 -224.586292)
					(mid 122.076597 -224.559876)
					(end 122.1486 -224.48774)
				)
			)
		)
	)
	(zone
		(layers "F.Cu" "B.Cu" "In1.Cu" "In2.Cu" "In3.Cu" "In4.Cu" "In5.Cu" "In6.Cu"
			"In7.Cu" "In8.Cu" "In9.Cu" "In10.Cu" "In11.Cu" "In12.Cu" "In13.Cu" "In14.Cu"
			"In15.Cu" "In16.Cu"
		)
		(hatch none 0.5)
		(connect_pads
			(clearance 0)
		)
		(min_thickness 0.25)
		(keepout
			(tracks not_allowed)
			(vias allowed)
			(pads allowed)
			(copperpour not_allowed)
			(footprints allowed)
		)
		(placement
			(enabled no)
			(sheetname "")
		)
		(fill
			(thermal_gap 0.5)
			(thermal_bridge_width 0.5)
			(island_removal_mode 0)
		)
		(polygon
			(pts
				(arc
					(start 99.281742 -221.94774)
					(mid 98.623882 -221.94774)
					(end 99.281742 -221.94774)
				)
			)
		)
	)
	(zone
		(layers "F.Cu" "B.Cu" "In1.Cu" "In2.Cu" "In3.Cu" "In4.Cu" "In5.Cu" "In6.Cu"
			"In7.Cu" "In8.Cu" "In9.Cu" "In10.Cu" "In11.Cu" "In12.Cu" "In13.Cu" "In14.Cu"
			"In15.Cu" "In16.Cu"
		)
		(hatch none 0.5)
		(connect_pads
			(clearance 0)
		)
		(min_thickness 0.25)
		(keepout
			(tracks not_allowed)
			(vias allowed)
			(pads allowed)
			(copperpour not_allowed)
			(footprints allowed)
		)
		(placement
			(enabled no)
			(sheetname "")
		)
		(fill
			(thermal_gap 0.5)
			(thermal_bridge_width 0.5)
			(island_removal_mode 0)
		)
		(polygon
			(pts
				(arc
					(start 120.239282 -220.319854)
					(mid 120.897142 -220.319854)
					(end 120.239282 -220.319854)
				)
			)
		)
	)
	(zone
		(layers "F.Cu" "B.Cu" "In1.Cu" "In2.Cu" "In3.Cu" "In4.Cu" "In5.Cu" "In6.Cu"
			"In7.Cu" "In8.Cu" "In9.Cu" "In10.Cu" "In11.Cu" "In12.Cu" "In13.Cu" "In14.Cu"
			"In15.Cu" "In16.Cu"
		)
		(hatch none 0.5)
		(connect_pads
			(clearance 0)
		)
		(min_thickness 0.25)
		(keepout
			(tracks not_allowed)
			(vias allowed)
			(pads allowed)
			(copperpour not_allowed)
			(footprints allowed)
		)
		(placement
			(enabled no)
			(sheetname "")
		)
		(fill
			(thermal_gap 0.5)
			(thermal_bridge_width 0.5)
			(island_removal_mode 0)
		)
		(polygon
			(pts
				(arc
					(start 351.92081 -220.319854)
					(mid 351.26295 -220.319854)
					(end 351.92081 -220.319854)
				)
			)
		)
	)
	(zone
		(layers "F.Cu" "B.Cu" "In1.Cu" "In2.Cu" "In3.Cu" "In4.Cu" "In5.Cu" "In6.Cu"
			"In7.Cu" "In8.Cu" "In9.Cu" "In10.Cu" "In11.Cu" "In12.Cu" "In13.Cu" "In14.Cu"
			"In15.Cu" "In16.Cu"
		)
		(hatch none 0.5)
		(connect_pads
			(clearance 0)
		)
		(min_thickness 0.25)
		(keepout
			(tracks not_allowed)
			(vias allowed)
			(pads allowed)
			(copperpour not_allowed)
			(footprints allowed)
		)
		(placement
			(enabled no)
			(sheetname "")
		)
		(fill
			(thermal_gap 0.5)
			(thermal_bridge_width 0.5)
			(island_removal_mode 0)
		)
		(polygon
			(pts
				(arc
					(start 375.41581 -218.692222)
					(mid 374.75795 -218.692222)
					(end 375.41581 -218.692222)
				)
			)
		)
	)
	(zone
		(layers "F.Cu" "B.Cu" "In1.Cu" "In2.Cu" "In3.Cu" "In4.Cu" "In5.Cu" "In6.Cu"
			"In7.Cu" "In8.Cu" "In9.Cu" "In10.Cu" "In11.Cu" "In12.Cu" "In13.Cu" "In14.Cu"
			"In15.Cu" "In16.Cu"
		)
		(hatch none 0.5)
		(connect_pads
			(clearance 0)
		)
		(min_thickness 0.25)
		(keepout
			(tracks not_allowed)
			(vias allowed)
			(pads allowed)
			(copperpour not_allowed)
			(footprints allowed)
		)
		(placement
			(enabled no)
			(sheetname "")
		)
		(fill
			(thermal_gap 0.5)
			(thermal_bridge_width 0.5)
			(island_removal_mode 0)
		)
		(polygon
			(pts
				(arc
					(start 359.43921 -220.319854)
					(mid 358.78135 -220.319854)
					(end 359.43921 -220.319854)
				)
			)
		)
	)
	(zone
		(layers "F.Cu" "B.Cu" "In1.Cu" "In2.Cu" "In3.Cu" "In4.Cu" "In5.Cu" "In6.Cu"
			"In7.Cu" "In8.Cu" "In9.Cu" "In10.Cu" "In11.Cu" "In12.Cu" "In13.Cu" "In14.Cu"
			"In15.Cu" "In16.Cu"
		)
		(hatch none 0.5)
		(connect_pads
			(clearance 0)
		)
		(min_thickness 0.25)
		(keepout
			(tracks not_allowed)
			(vias allowed)
			(pads allowed)
			(copperpour not_allowed)
			(footprints allowed)
		)
		(placement
			(enabled no)
			(sheetname "")
		)
		(fill
			(thermal_gap 0.5)
			(thermal_bridge_width 0.5)
			(island_removal_mode 0)
		)
		(polygon
			(pts
				(arc
					(start 159.977074 -400.477228)
					(mid 159.596074 -400.858228)
					(end 159.977074 -401.239228)
				)
				(arc
					(start 160.840674 -401.239228)
					(mid 161.221674 -400.858228)
					(end 160.840674 -400.477228)
				)
			)
		)
	)
	(zone
		(layers "F.Cu" "B.Cu" "In1.Cu" "In2.Cu" "In3.Cu" "In4.Cu" "In5.Cu" "In6.Cu"
			"In7.Cu" "In8.Cu" "In9.Cu" "In10.Cu" "In11.Cu" "In12.Cu" "In13.Cu" "In14.Cu"
			"In15.Cu" "In16.Cu"
		)
		(hatch none 0.5)
		(connect_pads
			(clearance 0)
		)
		(min_thickness 0.25)
		(keepout
			(tracks not_allowed)
			(vias allowed)
			(pads allowed)
			(copperpour not_allowed)
			(footprints allowed)
		)
		(placement
			(enabled no)
			(sheetname "")
		)
		(fill
			(thermal_gap 0.5)
			(thermal_bridge_width 0.5)
			(island_removal_mode 0)
		)
		(polygon
			(pts
				(arc
					(start 371.766592 -285.661354)
					(mid 371.108732 -285.661354)
					(end 371.766592 -285.661354)
				)
			)
		)
	)
	(zone
		(layers "F.Cu" "B.Cu" "In1.Cu" "In2.Cu" "In3.Cu" "In4.Cu" "In5.Cu" "In6.Cu"
			"In7.Cu" "In8.Cu" "In9.Cu" "In10.Cu" "In11.Cu" "In12.Cu" "In13.Cu" "In14.Cu"
			"In15.Cu" "In16.Cu"
		)
		(hatch none 0.5)
		(connect_pads
			(clearance 0)
		)
		(min_thickness 0.25)
		(keepout
			(tracks not_allowed)
			(vias allowed)
			(pads allowed)
			(copperpour not_allowed)
			(footprints allowed)
		)
		(placement
			(enabled no)
			(sheetname "")
		)
		(fill
			(thermal_gap 0.5)
			(thermal_bridge_width 0.5)
			(island_removal_mode 0)
		)
		(polygon
			(pts
				(arc
					(start 54.106318 -403.502876)
					(mid 53.725318 -403.883876)
					(end 54.106318 -404.264876)
				)
				(arc
					(start 54.969918 -404.264876)
					(mid 55.350918 -403.883876)
					(end 54.969918 -403.502876)
				)
			)
		)
	)
	(zone
		(layers "F.Cu" "B.Cu" "In1.Cu" "In2.Cu" "In3.Cu" "In4.Cu" "In5.Cu" "In6.Cu"
			"In7.Cu" "In8.Cu" "In9.Cu" "In10.Cu" "In11.Cu" "In12.Cu" "In13.Cu" "In14.Cu"
			"In15.Cu" "In16.Cu"
		)
		(hatch none 0.5)
		(connect_pads
			(clearance 0)
		)
		(min_thickness 0.25)
		(keepout
			(tracks not_allowed)
			(vias allowed)
			(pads allowed)
			(copperpour not_allowed)
			(footprints allowed)
		)
		(placement
			(enabled no)
			(sheetname "")
		)
		(fill
			(thermal_gap 0.5)
			(thermal_bridge_width 0.5)
			(island_removal_mode 0)
		)
		(polygon
			(pts
				(arc
					(start 350.352868 -221.035626)
					(mid 350.280879 -220.963467)
					(end 350.182434 -220.937074)
				)
				(arc
					(start 350.182434 -220.937074)
					(mid 350.04324 -220.99473)
					(end 349.985584 -221.133924)
				)
				(arc
					(start 349.985584 -221.133924)
					(mid 349.992341 -221.184805)
					(end 350.012 -221.232222)
				)
				(arc
					(start 350.481646 -222.046038)
					(mid 350.553635 -222.118197)
					(end 350.65208 -222.14459)
				)
				(arc
					(start 350.65208 -222.14459)
					(mid 350.791274 -222.086934)
					(end 350.84893 -221.94774)
				)
				(arc
					(start 350.84893 -221.94774)
					(mid 350.842173 -221.896859)
					(end 350.822514 -221.849442)
				)
			)
		)
	)
	(zone
		(layers "F.Cu" "B.Cu" "In1.Cu" "In2.Cu" "In3.Cu" "In4.Cu" "In5.Cu" "In6.Cu"
			"In7.Cu" "In8.Cu" "In9.Cu" "In10.Cu" "In11.Cu" "In12.Cu" "In13.Cu" "In14.Cu"
			"In15.Cu" "In16.Cu"
		)
		(hatch none 0.5)
		(connect_pads
			(clearance 0)
		)
		(min_thickness 0.25)
		(keepout
			(tracks not_allowed)
			(vias allowed)
			(pads allowed)
			(copperpour not_allowed)
			(footprints allowed)
		)
		(placement
			(enabled no)
			(sheetname "")
		)
		(fill
			(thermal_gap 0.5)
			(thermal_bridge_width 0.5)
			(island_removal_mode 0)
		)
		(polygon
			(pts
				(arc
					(start 248.767346 -5.1308)
					(mid 249.148346 -5.5118)
					(end 249.529346 -5.1308)
				)
				(arc
					(start 249.529346 -4.2672)
					(mid 249.148346 -3.8862)
					(end 248.767346 -4.2672)
				)
			)
		)
	)
	(zone
		(layers "F.Cu" "B.Cu" "In1.Cu" "In2.Cu" "In3.Cu" "In4.Cu" "In5.Cu" "In6.Cu"
			"In7.Cu" "In8.Cu" "In9.Cu" "In10.Cu" "In11.Cu" "In12.Cu" "In13.Cu" "In14.Cu"
			"In15.Cu" "In16.Cu"
		)
		(hatch none 0.5)
		(connect_pads
			(clearance 0)
		)
		(min_thickness 0.25)
		(keepout
			(tracks not_allowed)
			(vias allowed)
			(pads allowed)
			(copperpour not_allowed)
			(footprints allowed)
		)
		(placement
			(enabled no)
			(sheetname "")
		)
		(fill
			(thermal_gap 0.5)
			(thermal_bridge_width 0.5)
			(island_removal_mode 0)
		)
		(polygon
			(pts
				(arc
					(start 344.042492 -289.807142)
					(mid 343.384632 -289.807142)
					(end 344.042492 -289.807142)
				)
			)
		)
	)
	(zone
		(layers "F.Cu" "B.Cu" "In1.Cu" "In2.Cu" "In3.Cu" "In4.Cu" "In5.Cu" "In6.Cu"
			"In7.Cu" "In8.Cu" "In9.Cu" "In10.Cu" "In11.Cu" "In12.Cu" "In13.Cu" "In14.Cu"
			"In15.Cu" "In16.Cu"
		)
		(hatch none 0.5)
		(connect_pads
			(clearance 0)
		)
		(min_thickness 0.25)
		(keepout
			(tracks not_allowed)
			(vias allowed)
			(pads allowed)
			(copperpour not_allowed)
			(footprints allowed)
		)
		(placement
			(enabled no)
			(sheetname "")
		)
		(fill
			(thermal_gap 0.5)
			(thermal_bridge_width 0.5)
			(island_removal_mode 0)
		)
		(polygon
			(pts
				(arc
					(start 352.86061 -221.94774)
					(mid 352.20275 -221.94774)
					(end 352.86061 -221.94774)
				)
			)
		)
	)
	(zone
		(layers "F.Cu" "B.Cu" "In1.Cu" "In2.Cu" "In3.Cu" "In4.Cu" "In5.Cu" "In6.Cu"
			"In7.Cu" "In8.Cu" "In9.Cu" "In10.Cu" "In11.Cu" "In12.Cu" "In13.Cu" "In14.Cu"
			"In15.Cu" "In16.Cu"
		)
		(hatch none 0.5)
		(connect_pads
			(clearance 0)
		)
		(min_thickness 0.25)
		(keepout
			(tracks not_allowed)
			(vias allowed)
			(pads allowed)
			(copperpour not_allowed)
			(footprints allowed)
		)
		(placement
			(enabled no)
			(sheetname "")
		)
		(fill
			(thermal_gap 0.5)
			(thermal_bridge_width 0.5)
			(island_removal_mode 0)
		)
		(polygon
			(pts
				(arc
					(start 342.52281 -220.319854)
					(mid 341.86495 -220.319854)
					(end 342.52281 -220.319854)
				)
			)
		)
	)
	(zone
		(layers "F.Cu" "B.Cu" "In1.Cu" "In2.Cu" "In3.Cu" "In4.Cu" "In5.Cu" "In6.Cu"
			"In7.Cu" "In8.Cu" "In9.Cu" "In10.Cu" "In11.Cu" "In12.Cu" "In13.Cu" "In14.Cu"
			"In15.Cu" "In16.Cu"
		)
		(hatch none 0.5)
		(connect_pads
			(clearance 0)
		)
		(min_thickness 0.25)
		(keepout
			(tracks not_allowed)
			(vias allowed)
			(pads allowed)
			(copperpour not_allowed)
			(footprints allowed)
		)
		(placement
			(enabled no)
			(sheetname "")
		)
		(fill
			(thermal_gap 0.5)
			(thermal_bridge_width 0.5)
			(island_removal_mode 0)
		)
		(polygon
			(pts
				(arc
					(start 101.161342 -225.203258)
					(mid 100.503482 -225.203258)
					(end 101.161342 -225.203258)
				)
			)
		)
	)
	(zone
		(layers "F.Cu" "B.Cu" "In1.Cu" "In2.Cu" "In3.Cu" "In4.Cu" "In5.Cu" "In6.Cu"
			"In7.Cu" "In8.Cu" "In9.Cu" "In10.Cu" "In11.Cu" "In12.Cu" "In13.Cu" "In14.Cu"
			"In15.Cu" "In16.Cu"
		)
		(hatch none 0.5)
		(connect_pads
			(clearance 0)
		)
		(min_thickness 0.25)
		(keepout
			(tracks not_allowed)
			(vias allowed)
			(pads allowed)
			(copperpour not_allowed)
			(footprints allowed)
		)
		(placement
			(enabled no)
			(sheetname "")
		)
		(fill
			(thermal_gap 0.5)
			(thermal_bridge_width 0.5)
			(island_removal_mode 0)
		)
		(polygon
			(pts
				(arc
					(start 340.477348 -213.646766)
					(mid 340.40964 -213.574915)
					(end 340.314534 -213.548468)
				)
				(arc
					(start 340.314534 -213.548468)
					(mid 340.18432 -213.602404)
					(end 340.130384 -213.732618)
				)
				(arc
					(start 340.130384 -213.732618)
					(mid 340.135835 -213.776839)
					(end 340.15172 -213.81847)
				)
				(arc
					(start 340.621112 -214.708486)
					(mid 340.68882 -214.780337)
					(end 340.783926 -214.806784)
				)
				(arc
					(start 340.783926 -214.806784)
					(mid 340.91414 -214.752848)
					(end 340.968076 -214.622634)
				)
				(arc
					(start 340.968076 -214.622634)
					(mid 340.962625 -214.578413)
					(end 340.94674 -214.536782)
				)
			)
		)
	)
	(zone
		(layers "F.Cu" "B.Cu" "In1.Cu" "In2.Cu" "In3.Cu" "In4.Cu" "In5.Cu" "In6.Cu"
			"In7.Cu" "In8.Cu" "In9.Cu" "In10.Cu" "In11.Cu" "In12.Cu" "In13.Cu" "In14.Cu"
			"In15.Cu" "In16.Cu"
		)
		(hatch none 0.5)
		(connect_pads
			(clearance 0)
		)
		(min_thickness 0.25)
		(keepout
			(tracks not_allowed)
			(vias allowed)
			(pads allowed)
			(copperpour not_allowed)
			(footprints allowed)
		)
		(placement
			(enabled no)
			(sheetname "")
		)
		(fill
			(thermal_gap 0.5)
			(thermal_bridge_width 0.5)
			(island_removal_mode 0)
		)
		(polygon
			(pts
				(arc
					(start 128.415542 -217.064336)
					(mid 127.757682 -217.064336)
					(end 128.415542 -217.064336)
				)
			)
		)
	)
	(zone
		(layers "F.Cu" "B.Cu" "In1.Cu" "In2.Cu" "In3.Cu" "In4.Cu" "In5.Cu" "In6.Cu"
			"In7.Cu" "In8.Cu" "In9.Cu" "In10.Cu" "In11.Cu" "In12.Cu" "In13.Cu" "In14.Cu"
			"In15.Cu" "In16.Cu"
		)
		(hatch none 0.5)
		(connect_pads
			(clearance 0)
		)
		(min_thickness 0.25)
		(keepout
			(tracks not_allowed)
			(vias allowed)
			(pads allowed)
			(copperpour not_allowed)
			(footprints allowed)
		)
		(placement
			(enabled no)
			(sheetname "")
		)
		(fill
			(thermal_gap 0.5)
			(thermal_bridge_width 0.5)
			(island_removal_mode 0)
		)
		(polygon
			(pts
				(arc
					(start 351.561146 -275.08073)
					(mid 350.903286 -275.08073)
					(end 351.561146 -275.08073)
				)
			)
		)
	)
	(zone
		(layers "F.Cu" "B.Cu" "In1.Cu" "In2.Cu" "In3.Cu" "In4.Cu" "In5.Cu" "In6.Cu"
			"In7.Cu" "In8.Cu" "In9.Cu" "In10.Cu" "In11.Cu" "In12.Cu" "In13.Cu" "In14.Cu"
			"In15.Cu" "In16.Cu"
		)
		(hatch none 0.5)
		(connect_pads
			(clearance 0)
		)
		(min_thickness 0.25)
		(keepout
			(tracks not_allowed)
			(vias allowed)
			(pads allowed)
			(copperpour not_allowed)
			(footprints allowed)
		)
		(placement
			(enabled no)
			(sheetname "")
		)
		(fill
			(thermal_gap 0.5)
			(thermal_bridge_width 0.5)
			(island_removal_mode 0)
		)
		(polygon
			(pts
				(arc
					(start 124.186696 -221.133924)
					(mid 123.528836 -221.133924)
					(end 124.186696 -221.133924)
				)
			)
		)
	)
	(zone
		(layers "F.Cu" "B.Cu" "In1.Cu" "In2.Cu" "In3.Cu" "In4.Cu" "In5.Cu" "In6.Cu"
			"In7.Cu" "In8.Cu" "In9.Cu" "In10.Cu" "In11.Cu" "In12.Cu" "In13.Cu" "In14.Cu"
			"In15.Cu" "In16.Cu"
		)
		(hatch none 0.5)
		(connect_pads
			(clearance 0)
		)
		(min_thickness 0.25)
		(keepout
			(tracks not_allowed)
			(vias allowed)
			(pads allowed)
			(copperpour not_allowed)
			(footprints allowed)
		)
		(placement
			(enabled no)
			(sheetname "")
		)
		(fill
			(thermal_gap 0.5)
			(thermal_bridge_width 0.5)
			(island_removal_mode 0)
		)
		(polygon
			(pts
				(arc
					(start 329.832208 -409.649168)
					(mid 329.451208 -410.030168)
					(end 329.832208 -410.411168)
				)
				(arc
					(start 330.695808 -410.411168)
					(mid 331.076808 -410.030168)
					(end 330.695808 -409.649168)
				)
			)
		)
	)
	(zone
		(layers "F.Cu" "B.Cu" "In1.Cu" "In2.Cu" "In3.Cu" "In4.Cu" "In5.Cu" "In6.Cu"
			"In7.Cu" "In8.Cu" "In9.Cu" "In10.Cu" "In11.Cu" "In12.Cu" "In13.Cu" "In14.Cu"
			"In15.Cu" "In16.Cu"
		)
		(hatch none 0.5)
		(connect_pads
			(clearance 0)
		)
		(min_thickness 0.25)
		(keepout
			(tracks not_allowed)
			(vias allowed)
			(pads allowed)
			(copperpour not_allowed)
			(footprints allowed)
		)
		(placement
			(enabled no)
			(sheetname "")
		)
		(fill
			(thermal_gap 0.5)
			(thermal_bridge_width 0.5)
			(island_removal_mode 0)
		)
		(polygon
			(pts
				(arc
					(start 354.414836 -43.229784)
					(mid 354.033836 -43.610784)
					(end 354.414836 -43.991784)
				)
				(arc
					(start 355.278436 -43.991784)
					(mid 355.659436 -43.610784)
					(end 355.278436 -43.229784)
				)
			)
		)
	)
	(zone
		(layers "F.Cu" "B.Cu" "In1.Cu" "In2.Cu" "In3.Cu" "In4.Cu" "In5.Cu" "In6.Cu"
			"In7.Cu" "In8.Cu" "In9.Cu" "In10.Cu" "In11.Cu" "In12.Cu" "In13.Cu" "In14.Cu"
			"In15.Cu" "In16.Cu"
		)
		(hatch none 0.5)
		(connect_pads
			(clearance 0)
		)
		(min_thickness 0.25)
		(keepout
			(tracks not_allowed)
			(vias allowed)
			(pads allowed)
			(copperpour not_allowed)
			(footprints allowed)
		)
		(placement
			(enabled no)
			(sheetname "")
		)
		(fill
			(thermal_gap 0.5)
			(thermal_bridge_width 0.5)
			(island_removal_mode 0)
		)
		(polygon
			(pts
				(arc
					(start 117.137942 -217.064336)
					(mid 116.480082 -217.064336)
					(end 117.137942 -217.064336)
				)
			)
		)
	)
	(zone
		(layers "F.Cu" "B.Cu" "In1.Cu" "In2.Cu" "In3.Cu" "In4.Cu" "In5.Cu" "In6.Cu"
			"In7.Cu" "In8.Cu" "In9.Cu" "In10.Cu" "In11.Cu" "In12.Cu" "In13.Cu" "In14.Cu"
			"In15.Cu" "In16.Cu"
		)
		(hatch none 0.5)
		(connect_pads
			(clearance 0)
		)
		(min_thickness 0.25)
		(keepout
			(tracks not_allowed)
			(vias allowed)
			(pads allowed)
			(copperpour not_allowed)
			(footprints allowed)
		)
		(placement
			(enabled no)
			(sheetname "")
		)
		(fill
			(thermal_gap 0.5)
			(thermal_bridge_width 0.5)
			(island_removal_mode 0)
		)
		(polygon
			(pts
				(arc
					(start 417.37153 -400.477228)
					(mid 416.99053 -400.858228)
					(end 417.37153 -401.239228)
				)
				(arc
					(start 418.23513 -401.239228)
					(mid 418.61613 -400.858228)
					(end 418.23513 -400.477228)
				)
			)
		)
	)
	(zone
		(layers "F.Cu" "B.Cu" "In1.Cu" "In2.Cu" "In3.Cu" "In4.Cu" "In5.Cu" "In6.Cu"
			"In7.Cu" "In8.Cu" "In9.Cu" "In10.Cu" "In11.Cu" "In12.Cu" "In13.Cu" "In14.Cu"
			"In15.Cu" "In16.Cu"
		)
		(hatch none 0.5)
		(connect_pads
			(clearance 0)
		)
		(min_thickness 0.25)
		(keepout
			(tracks not_allowed)
			(vias allowed)
			(pads allowed)
			(copperpour not_allowed)
			(footprints allowed)
		)
		(placement
			(enabled no)
			(sheetname "")
		)
		(fill
			(thermal_gap 0.5)
			(thermal_bridge_width 0.5)
			(island_removal_mode 0)
		)
		(polygon
			(pts
				(arc
					(start 379.48616 -221.231968)
					(mid 379.505844 -221.184558)
					(end 379.512576 -221.13367)
				)
				(arc
					(start 379.512576 -221.13367)
					(mid 379.45492 -220.994476)
					(end 379.315726 -220.93682)
				)
				(arc
					(start 379.315726 -220.93682)
					(mid 379.217295 -220.963236)
					(end 379.145292 -221.035372)
				)
				(arc
					(start 378.675646 -221.849442)
					(mid 378.655962 -221.896852)
					(end 378.64923 -221.94774)
				)
				(arc
					(start 378.64923 -221.94774)
					(mid 378.706886 -222.086934)
					(end 378.84608 -222.14459)
				)
				(arc
					(start 378.84608 -222.14459)
					(mid 378.944511 -222.118174)
					(end 379.016514 -222.046038)
				)
			)
		)
	)
	(zone
		(layers "F.Cu" "B.Cu" "In1.Cu" "In2.Cu" "In3.Cu" "In4.Cu" "In5.Cu" "In6.Cu"
			"In7.Cu" "In8.Cu" "In9.Cu" "In10.Cu" "In11.Cu" "In12.Cu" "In13.Cu" "In14.Cu"
			"In15.Cu" "In16.Cu"
		)
		(hatch none 0.5)
		(connect_pads
			(clearance 0)
		)
		(min_thickness 0.25)
		(keepout
			(tracks not_allowed)
			(vias allowed)
			(pads allowed)
			(copperpour not_allowed)
			(footprints allowed)
		)
		(placement
			(enabled no)
			(sheetname "")
		)
		(fill
			(thermal_gap 0.5)
			(thermal_bridge_width 0.5)
			(island_removal_mode 0)
		)
		(polygon
			(pts
				(arc
					(start 121.836942 -221.94774)
					(mid 121.179082 -221.94774)
					(end 121.836942 -221.94774)
				)
			)
		)
	)
	(zone
		(layers "F.Cu" "B.Cu" "In1.Cu" "In2.Cu" "In3.Cu" "In4.Cu" "In5.Cu" "In6.Cu"
			"In7.Cu" "In8.Cu" "In9.Cu" "In10.Cu" "In11.Cu" "In12.Cu" "In13.Cu" "In14.Cu"
			"In15.Cu" "In16.Cu"
		)
		(hatch none 0.5)
		(connect_pads
			(clearance 0)
		)
		(min_thickness 0.25)
		(keepout
			(tracks not_allowed)
			(vias allowed)
			(pads allowed)
			(copperpour not_allowed)
			(footprints allowed)
		)
		(placement
			(enabled no)
			(sheetname "")
		)
		(fill
			(thermal_gap 0.5)
			(thermal_bridge_width 0.5)
			(island_removal_mode 0)
		)
		(polygon
			(pts
				(arc
					(start 363.040422 -216.966292)
					(mid 362.968433 -216.894133)
					(end 362.869988 -216.86774)
				)
				(arc
					(start 362.869988 -216.86774)
					(mid 362.730794 -216.925396)
					(end 362.673138 -217.06459)
				)
				(arc
					(start 362.673138 -217.06459)
					(mid 362.679895 -217.115471)
					(end 362.699554 -217.162888)
				)
				(arc
					(start 363.1692 -217.976704)
					(mid 363.241189 -218.048863)
					(end 363.339634 -218.075256)
				)
				(arc
					(start 363.339634 -218.075256)
					(mid 363.478828 -218.0176)
					(end 363.536484 -217.878406)
				)
				(arc
					(start 363.536484 -217.878406)
					(mid 363.529727 -217.827525)
					(end 363.510068 -217.780108)
				)
			)
		)
	)
	(zone
		(layers "F.Cu" "B.Cu" "In1.Cu" "In2.Cu" "In3.Cu" "In4.Cu" "In5.Cu" "In6.Cu"
			"In7.Cu" "In8.Cu" "In9.Cu" "In10.Cu" "In11.Cu" "In12.Cu" "In13.Cu" "In14.Cu"
			"In15.Cu" "In16.Cu"
		)
		(hatch none 0.5)
		(connect_pads
			(clearance 0)
		)
		(min_thickness 0.25)
		(keepout
			(tracks not_allowed)
			(vias allowed)
			(pads allowed)
			(copperpour not_allowed)
			(footprints allowed)
		)
		(placement
			(enabled no)
			(sheetname "")
		)
		(fill
			(thermal_gap 0.5)
			(thermal_bridge_width 0.5)
			(island_removal_mode 0)
		)
		(polygon
			(pts
				(arc
					(start 97.872296 -217.878406)
					(mid 97.214436 -217.878406)
					(end 97.872296 -217.878406)
				)
			)
		)
	)
	(zone
		(layers "F.Cu" "B.Cu" "In1.Cu" "In2.Cu" "In3.Cu" "In4.Cu" "In5.Cu" "In6.Cu"
			"In7.Cu" "In8.Cu" "In9.Cu" "In10.Cu" "In11.Cu" "In12.Cu" "In13.Cu" "In14.Cu"
			"In15.Cu" "In16.Cu"
		)
		(hatch none 0.5)
		(connect_pads
			(clearance 0)
		)
		(min_thickness 0.25)
		(keepout
			(tracks not_allowed)
			(vias allowed)
			(pads allowed)
			(copperpour not_allowed)
			(footprints allowed)
		)
		(placement
			(enabled no)
			(sheetname "")
		)
		(fill
			(thermal_gap 0.5)
			(thermal_bridge_width 0.5)
			(island_removal_mode 0)
		)
		(polygon
			(pts
				(arc
					(start 342.364314 -220.418152)
					(mid 342.383998 -220.370742)
					(end 342.39073 -220.319854)
				)
				(arc
					(start 342.39073 -220.319854)
					(mid 342.333074 -220.18066)
					(end 342.19388 -220.123004)
				)
				(arc
					(start 342.19388 -220.123004)
					(mid 342.095449 -220.14942)
					(end 342.023446 -220.221556)
				)
				(arc
					(start 341.5538 -221.035626)
					(mid 341.534116 -221.083036)
					(end 341.527384 -221.133924)
				)
				(arc
					(start 341.527384 -221.133924)
					(mid 341.58504 -221.273118)
					(end 341.724234 -221.330774)
				)
				(arc
					(start 341.724234 -221.330774)
					(mid 341.822665 -221.304358)
					(end 341.894668 -221.232222)
				)
			)
		)
	)
	(zone
		(layers "F.Cu" "B.Cu" "In1.Cu" "In2.Cu" "In3.Cu" "In4.Cu" "In5.Cu" "In6.Cu"
			"In7.Cu" "In8.Cu" "In9.Cu" "In10.Cu" "In11.Cu" "In12.Cu" "In13.Cu" "In14.Cu"
			"In15.Cu" "In16.Cu"
		)
		(hatch none 0.5)
		(connect_pads
			(clearance 0)
		)
		(min_thickness 0.25)
		(keepout
			(tracks not_allowed)
			(vias allowed)
			(pads allowed)
			(copperpour not_allowed)
			(footprints allowed)
		)
		(placement
			(enabled no)
			(sheetname "")
		)
		(fill
			(thermal_gap 0.5)
			(thermal_bridge_width 0.5)
			(island_removal_mode 0)
		)
		(polygon
			(pts
				(arc
					(start 89.414096 -217.878406)
					(mid 88.756236 -217.878406)
					(end 89.414096 -217.878406)
				)
			)
		)
	)
	(zone
		(layers "F.Cu" "B.Cu" "In1.Cu" "In2.Cu" "In3.Cu" "In4.Cu" "In5.Cu" "In6.Cu"
			"In7.Cu" "In8.Cu" "In9.Cu" "In10.Cu" "In11.Cu" "In12.Cu" "In13.Cu" "In14.Cu"
			"In15.Cu" "In16.Cu"
		)
		(hatch none 0.5)
		(connect_pads
			(clearance 0)
		)
		(min_thickness 0.25)
		(keepout
			(tracks not_allowed)
			(vias allowed)
			(pads allowed)
			(copperpour not_allowed)
			(footprints allowed)
		)
		(placement
			(enabled no)
			(sheetname "")
		)
		(fill
			(thermal_gap 0.5)
			(thermal_bridge_width 0.5)
			(island_removal_mode 0)
		)
		(polygon
			(pts
				(arc
					(start 107.739942 -223.575626)
					(mid 107.082082 -223.575626)
					(end 107.739942 -223.575626)
				)
			)
		)
	)
	(zone
		(layers "F.Cu" "B.Cu" "In1.Cu" "In2.Cu" "In3.Cu" "In4.Cu" "In5.Cu" "In6.Cu"
			"In7.Cu" "In8.Cu" "In9.Cu" "In10.Cu" "In11.Cu" "In12.Cu" "In13.Cu" "In14.Cu"
			"In15.Cu" "In16.Cu"
		)
		(hatch none 0.5)
		(connect_pads
			(clearance 0)
		)
		(min_thickness 0.25)
		(keepout
			(tracks not_allowed)
			(vias allowed)
			(pads allowed)
			(copperpour not_allowed)
			(footprints allowed)
		)
		(placement
			(enabled no)
			(sheetname "")
		)
		(fill
			(thermal_gap 0.5)
			(thermal_bridge_width 0.5)
			(island_removal_mode 0)
		)
		(polygon
			(pts
				(arc
					(start 369.886992 -285.661354)
					(mid 369.229132 -285.661354)
					(end 369.886992 -285.661354)
				)
			)
		)
	)
	(zone
		(layers "F.Cu" "B.Cu" "In1.Cu" "In2.Cu" "In3.Cu" "In4.Cu" "In5.Cu" "In6.Cu"
			"In7.Cu" "In8.Cu" "In9.Cu" "In10.Cu" "In11.Cu" "In12.Cu" "In13.Cu" "In14.Cu"
			"In15.Cu" "In16.Cu"
		)
		(hatch none 0.5)
		(connect_pads
			(clearance 0)
		)
		(min_thickness 0.25)
		(keepout
			(tracks not_allowed)
			(vias allowed)
			(pads allowed)
			(copperpour not_allowed)
			(footprints allowed)
		)
		(placement
			(enabled no)
			(sheetname "")
		)
		(fill
			(thermal_gap 0.5)
			(thermal_bridge_width 0.5)
			(island_removal_mode 0)
		)
		(polygon
			(pts
				(arc
					(start 60.14212 -421.760396)
					(mid 60.164438 -421.814278)
					(end 60.21832 -421.836596)
				)
				(arc
					(start 61.15812 -421.836596)
					(mid 61.212002 -421.814278)
					(end 61.23432 -421.760396)
				)
				(arc
					(start 61.23432 -419.218872)
					(mid 61.212002 -419.16499)
					(end 61.15812 -419.142672)
				)
				(arc
					(start 60.21832 -419.142672)
					(mid 60.164438 -419.16499)
					(end 60.14212 -419.218872)
				)
			)
		)
	)
	(zone
		(layers "F.Cu" "B.Cu" "In1.Cu" "In2.Cu" "In3.Cu" "In4.Cu" "In5.Cu" "In6.Cu"
			"In7.Cu" "In8.Cu" "In9.Cu" "In10.Cu" "In11.Cu" "In12.Cu" "In13.Cu" "In14.Cu"
			"In15.Cu" "In16.Cu"
		)
		(hatch none 0.5)
		(connect_pads
			(clearance 0)
		)
		(min_thickness 0.25)
		(keepout
			(tracks not_allowed)
			(vias allowed)
			(pads allowed)
			(copperpour not_allowed)
			(footprints allowed)
		)
		(placement
			(enabled no)
			(sheetname "")
		)
		(fill
			(thermal_gap 0.5)
			(thermal_bridge_width 0.5)
			(island_removal_mode 0)
		)
		(polygon
			(pts
				(arc
					(start 346.593668 -217.780108)
					(mid 346.521679 -217.707949)
					(end 346.423234 -217.681556)
				)
				(arc
					(start 346.423234 -217.681556)
					(mid 346.28404 -217.739212)
					(end 346.226384 -217.878406)
				)
				(arc
					(start 346.226384 -217.878406)
					(mid 346.233141 -217.929287)
					(end 346.2528 -217.976704)
				)
				(arc
					(start 346.722446 -218.79052)
					(mid 346.794435 -218.862679)
					(end 346.89288 -218.889072)
				)
				(arc
					(start 346.89288 -218.889072)
					(mid 347.032074 -218.831416)
					(end 347.08973 -218.692222)
				)
				(arc
					(start 347.08973 -218.692222)
					(mid 347.082973 -218.641341)
					(end 347.063314 -218.593924)
				)
			)
		)
	)
	(zone
		(layers "F.Cu" "B.Cu" "In1.Cu" "In2.Cu" "In3.Cu" "In4.Cu" "In5.Cu" "In6.Cu"
			"In7.Cu" "In8.Cu" "In9.Cu" "In10.Cu" "In11.Cu" "In12.Cu" "In13.Cu" "In14.Cu"
			"In15.Cu" "In16.Cu"
		)
		(hatch none 0.5)
		(connect_pads
			(clearance 0)
		)
		(min_thickness 0.25)
		(keepout
			(tracks not_allowed)
			(vias allowed)
			(pads allowed)
			(copperpour not_allowed)
			(footprints allowed)
		)
		(placement
			(enabled no)
			(sheetname "")
		)
		(fill
			(thermal_gap 0.5)
			(thermal_bridge_width 0.5)
			(island_removal_mode 0)
		)
		(polygon
			(pts
				(arc
					(start 76.895198 -409.649168)
					(mid 76.514198 -410.030168)
					(end 76.895198 -410.411168)
				)
				(arc
					(start 77.758798 -410.411168)
					(mid 78.139798 -410.030168)
					(end 77.758798 -409.649168)
				)
			)
		)
	)
	(zone
		(layers "F.Cu" "B.Cu" "In1.Cu" "In2.Cu" "In3.Cu" "In4.Cu" "In5.Cu" "In6.Cu"
			"In7.Cu" "In8.Cu" "In9.Cu" "In10.Cu" "In11.Cu" "In12.Cu" "In13.Cu" "In14.Cu"
			"In15.Cu" "In16.Cu"
		)
		(hatch none 0.5)
		(connect_pads
			(clearance 0)
		)
		(min_thickness 0.25)
		(keepout
			(tracks not_allowed)
			(vias allowed)
			(pads allowed)
			(copperpour not_allowed)
			(footprints allowed)
		)
		(placement
			(enabled no)
			(sheetname "")
		)
		(fill
			(thermal_gap 0.5)
			(thermal_bridge_width 0.5)
			(island_removal_mode 0)
		)
		(polygon
			(pts
				(arc
					(start 163.040314 -403.502876)
					(mid 162.659314 -403.883876)
					(end 163.040314 -404.264876)
				)
				(arc
					(start 163.903914 -404.264876)
					(mid 164.284914 -403.883876)
					(end 163.903914 -403.502876)
				)
			)
		)
	)
	(zone
		(layers "F.Cu" "B.Cu" "In1.Cu" "In2.Cu" "In3.Cu" "In4.Cu" "In5.Cu" "In6.Cu"
			"In7.Cu" "In8.Cu" "In9.Cu" "In10.Cu" "In11.Cu" "In12.Cu" "In13.Cu" "In14.Cu"
			"In15.Cu" "In16.Cu"
		)
		(hatch none 0.5)
		(connect_pads
			(clearance 0)
		)
		(min_thickness 0.25)
		(keepout
			(tracks not_allowed)
			(vias allowed)
			(pads allowed)
			(copperpour not_allowed)
			(footprints allowed)
		)
		(placement
			(enabled no)
			(sheetname "")
		)
		(fill
			(thermal_gap 0.5)
			(thermal_bridge_width 0.5)
			(island_removal_mode 0)
		)
		(polygon
			(pts
				(arc
					(start 89.413588 -216.25052)
					(mid 88.755728 -216.25052)
					(end 89.413588 -216.25052)
				)
			)
		)
	)
	(zone
		(layers "F.Cu" "B.Cu" "In1.Cu" "In2.Cu" "In3.Cu" "In4.Cu" "In5.Cu" "In6.Cu"
			"In7.Cu" "In8.Cu" "In9.Cu" "In10.Cu" "In11.Cu" "In12.Cu" "In13.Cu" "In14.Cu"
			"In15.Cu" "In16.Cu"
		)
		(hatch none 0.5)
		(connect_pads
			(clearance 0)
		)
		(min_thickness 0.25)
		(keepout
			(tracks not_allowed)
			(vias allowed)
			(pads allowed)
			(copperpour not_allowed)
			(footprints allowed)
		)
		(placement
			(enabled no)
			(sheetname "")
		)
		(fill
			(thermal_gap 0.5)
			(thermal_bridge_width 0.5)
			(island_removal_mode 0)
		)
		(polygon
			(pts
				(arc
					(start 101.630988 -214.622634)
					(mid 100.973128 -214.622634)
					(end 101.630988 -214.622634)
				)
			)
		)
	)
	(zone
		(layers "F.Cu" "B.Cu" "In1.Cu" "In2.Cu" "In3.Cu" "In4.Cu" "In5.Cu" "In6.Cu"
			"In7.Cu" "In8.Cu" "In9.Cu" "In10.Cu" "In11.Cu" "In12.Cu" "In13.Cu" "In14.Cu"
			"In15.Cu" "In16.Cu"
		)
		(hatch none 0.5)
		(connect_pads
			(clearance 0)
		)
		(min_thickness 0.25)
		(keepout
			(tracks not_allowed)
			(vias allowed)
			(pads allowed)
			(copperpour not_allowed)
			(footprints allowed)
		)
		(placement
			(enabled no)
			(sheetname "")
		)
		(fill
			(thermal_gap 0.5)
			(thermal_bridge_width 0.5)
			(island_removal_mode 0)
		)
		(polygon
			(pts
				(arc
					(start 342.163146 -286.475424)
					(mid 341.505286 -286.475424)
					(end 342.163146 -286.475424)
				)
			)
		)
	)
	(zone
		(layers "F.Cu" "B.Cu" "In1.Cu" "In2.Cu" "In3.Cu" "In4.Cu" "In5.Cu" "In6.Cu"
			"In7.Cu" "In8.Cu" "In9.Cu" "In10.Cu" "In11.Cu" "In12.Cu" "In13.Cu" "In14.Cu"
			"In15.Cu" "In16.Cu"
		)
		(hatch none 0.5)
		(connect_pads
			(clearance 0)
		)
		(min_thickness 0.25)
		(keepout
			(tracks allowed)
			(vias allowed)
			(pads allowed)
			(copperpour allowed)
			(footprints not_allowed)
		)
		(placement
			(enabled no)
			(sheetname "")
		)
		(fill
			(thermal_gap 0.5)
			(thermal_bridge_width 0.5)
			(island_removal_mode 0)
		)
		(polygon
			(pts
				(arc
					(start 420.787068 -74.767948)
					(mid 426.803058 -80.783938)
					(end 432.819048 -74.767948)
				)
				(arc
					(start 432.819048 -66.06794)
					(mid 426.803058 -60.05195)
					(end 420.787068 -66.06794)
				)
			)
		)
	)
	(zone
		(layers "F.Cu" "B.Cu" "In1.Cu" "In2.Cu" "In3.Cu" "In4.Cu" "In5.Cu" "In6.Cu"
			"In7.Cu" "In8.Cu" "In9.Cu" "In10.Cu" "In11.Cu" "In12.Cu" "In13.Cu" "In14.Cu"
			"In15.Cu" "In16.Cu"
		)
		(hatch none 0.5)
		(connect_pads
			(clearance 0)
		)
		(min_thickness 0.25)
		(keepout
			(tracks not_allowed)
			(vias allowed)
			(pads allowed)
			(copperpour not_allowed)
			(footprints allowed)
		)
		(placement
			(enabled no)
			(sheetname "")
		)
		(fill
			(thermal_gap 0.5)
			(thermal_bridge_width 0.5)
			(island_removal_mode 0)
		)
		(polygon
			(pts
				(arc
					(start 113.378742 -217.064336)
					(mid 112.720882 -217.064336)
					(end 113.378742 -217.064336)
				)
			)
		)
	)
	(zone
		(layers "F.Cu" "B.Cu" "In1.Cu" "In2.Cu" "In3.Cu" "In4.Cu" "In5.Cu" "In6.Cu"
			"In7.Cu" "In8.Cu" "In9.Cu" "In10.Cu" "In11.Cu" "In12.Cu" "In13.Cu" "In14.Cu"
			"In15.Cu" "In16.Cu"
		)
		(hatch none 0.5)
		(connect_pads
			(clearance 0)
		)
		(min_thickness 0.25)
		(keepout
			(tracks not_allowed)
			(vias allowed)
			(pads allowed)
			(copperpour not_allowed)
			(footprints allowed)
		)
		(placement
			(enabled no)
			(sheetname "")
		)
		(fill
			(thermal_gap 0.5)
			(thermal_bridge_width 0.5)
			(island_removal_mode 0)
		)
		(polygon
			(pts
				(arc
					(start 125.907292 -221.231968)
					(mid 125.926976 -221.184558)
					(end 125.933708 -221.13367)
				)
				(arc
					(start 125.933708 -221.13367)
					(mid 125.876052 -220.994476)
					(end 125.736858 -220.93682)
				)
				(arc
					(start 125.736858 -220.93682)
					(mid 125.638427 -220.963236)
					(end 125.566424 -221.035372)
				)
				(arc
					(start 125.096778 -221.849442)
					(mid 125.077094 -221.896852)
					(end 125.070362 -221.94774)
				)
				(arc
					(start 125.070362 -221.94774)
					(mid 125.128018 -222.086934)
					(end 125.267212 -222.14459)
				)
				(arc
					(start 125.267212 -222.14459)
					(mid 125.365643 -222.118174)
					(end 125.437646 -222.046038)
				)
			)
		)
	)
	(zone
		(layers "F.Cu" "B.Cu" "In1.Cu" "In2.Cu" "In3.Cu" "In4.Cu" "In5.Cu" "In6.Cu"
			"In7.Cu" "In8.Cu" "In9.Cu" "In10.Cu" "In11.Cu" "In12.Cu" "In13.Cu" "In14.Cu"
			"In15.Cu" "In16.Cu"
		)
		(hatch none 0.5)
		(connect_pads
			(clearance 0)
		)
		(min_thickness 0.25)
		(keepout
			(tracks not_allowed)
			(vias allowed)
			(pads allowed)
			(copperpour not_allowed)
			(footprints allowed)
		)
		(placement
			(enabled no)
			(sheetname "")
		)
		(fill
			(thermal_gap 0.5)
			(thermal_bridge_width 0.5)
			(island_removal_mode 0)
		)
		(polygon
			(pts
				(arc
					(start 124.656342 -213.732618)
					(mid 123.998482 -213.732618)
					(end 124.656342 -213.732618)
				)
			)
		)
	)
	(zone
		(layers "F.Cu" "B.Cu" "In1.Cu" "In2.Cu" "In3.Cu" "In4.Cu" "In5.Cu" "In6.Cu"
			"In7.Cu" "In8.Cu" "In9.Cu" "In10.Cu" "In11.Cu" "In12.Cu" "In13.Cu" "In14.Cu"
			"In15.Cu" "In16.Cu"
		)
		(hatch none 0.5)
		(connect_pads
			(clearance 0)
		)
		(min_thickness 0.25)
		(keepout
			(tracks not_allowed)
			(vias allowed)
			(pads allowed)
			(copperpour not_allowed)
			(footprints allowed)
		)
		(placement
			(enabled no)
			(sheetname "")
		)
		(fill
			(thermal_gap 0.5)
			(thermal_bridge_width 0.5)
			(island_removal_mode 0)
		)
		(polygon
			(pts
				(arc
					(start 116.198142 -218.692222)
					(mid 115.540282 -218.692222)
					(end 116.198142 -218.692222)
				)
			)
		)
	)
	(zone
		(layers "F.Cu" "B.Cu" "In1.Cu" "In2.Cu" "In3.Cu" "In4.Cu" "In5.Cu" "In6.Cu"
			"In7.Cu" "In8.Cu" "In9.Cu" "In10.Cu" "In11.Cu" "In12.Cu" "In13.Cu" "In14.Cu"
			"In15.Cu" "In16.Cu"
		)
		(hatch none 0.5)
		(connect_pads
			(clearance 0)
		)
		(min_thickness 0.25)
		(keepout
			(tracks not_allowed)
			(vias allowed)
			(pads allowed)
			(copperpour not_allowed)
			(footprints allowed)
		)
		(placement
			(enabled no)
			(sheetname "")
		)
		(fill
			(thermal_gap 0.5)
			(thermal_bridge_width 0.5)
			(island_removal_mode 0)
		)
		(polygon
			(pts
				(arc
					(start 133.506464 -285.661354)
					(mid 134.164324 -285.661354)
					(end 133.506464 -285.661354)
				)
			)
		)
	)
	(zone
		(layers "F.Cu" "B.Cu" "In1.Cu" "In2.Cu" "In3.Cu" "In4.Cu" "In5.Cu" "In6.Cu"
			"In7.Cu" "In8.Cu" "In9.Cu" "In10.Cu" "In11.Cu" "In12.Cu" "In13.Cu" "In14.Cu"
			"In15.Cu" "In16.Cu"
		)
		(hatch none 0.5)
		(connect_pads
			(clearance 0)
		)
		(min_thickness 0.25)
		(keepout
			(tracks not_allowed)
			(vias allowed)
			(pads allowed)
			(copperpour not_allowed)
			(footprints allowed)
		)
		(placement
			(enabled no)
			(sheetname "")
		)
		(fill
			(thermal_gap 0.5)
			(thermal_bridge_width 0.5)
			(island_removal_mode 0)
		)
		(polygon
			(pts
				(arc
					(start 332.090268 -78.358492)
					(mid 332.471268 -77.977492)
					(end 332.090268 -77.596492)
				)
				(arc
					(start 331.226668 -77.596492)
					(mid 330.845668 -77.977492)
					(end 331.226668 -78.358492)
				)
			)
		)
	)
	(zone
		(layers "F.Cu" "B.Cu" "In1.Cu" "In2.Cu" "In3.Cu" "In4.Cu" "In5.Cu" "In6.Cu"
			"In7.Cu" "In8.Cu" "In9.Cu" "In10.Cu" "In11.Cu" "In12.Cu" "In13.Cu" "In14.Cu"
			"In15.Cu" "In16.Cu"
		)
		(hatch none 0.5)
		(connect_pads
			(clearance 0)
		)
		(min_thickness 0.25)
		(keepout
			(tracks not_allowed)
			(vias allowed)
			(pads allowed)
			(copperpour not_allowed)
			(footprints allowed)
		)
		(placement
			(enabled no)
			(sheetname "")
		)
		(fill
			(thermal_gap 0.5)
			(thermal_bridge_width 0.5)
			(island_removal_mode 0)
		)
		(polygon
			(pts
				(arc
					(start 64.142112 -425.360592)
					(mid 64.16443 -425.414474)
					(end 64.218312 -425.436792)
				)
				(arc
					(start 65.158112 -425.436792)
					(mid 65.211994 -425.414474)
					(end 65.234312 -425.360592)
				)
				(arc
					(start 65.234312 -422.819068)
					(mid 65.211994 -422.765186)
					(end 65.158112 -422.742868)
				)
				(arc
					(start 64.218312 -422.742868)
					(mid 64.16443 -422.765186)
					(end 64.142112 -422.819068)
				)
			)
		)
	)
	(zone
		(layers "F.Cu" "B.Cu" "In1.Cu" "In2.Cu" "In3.Cu" "In4.Cu" "In5.Cu" "In6.Cu"
			"In7.Cu" "In8.Cu" "In9.Cu" "In10.Cu" "In11.Cu" "In12.Cu" "In13.Cu" "In14.Cu"
			"In15.Cu" "In16.Cu"
		)
		(hatch none 0.5)
		(connect_pads
			(clearance 0)
		)
		(min_thickness 0.25)
		(keepout
			(tracks not_allowed)
			(vias allowed)
			(pads allowed)
			(copperpour not_allowed)
			(footprints allowed)
		)
		(placement
			(enabled no)
			(sheetname "")
		)
		(fill
			(thermal_gap 0.5)
			(thermal_bridge_width 0.5)
			(island_removal_mode 0)
		)
		(polygon
			(pts
				(arc
					(start 348.892114 -44.43222)
					(mid 348.511114 -44.81322)
					(end 348.892114 -45.19422)
				)
				(arc
					(start 349.755714 -45.19422)
					(mid 350.136714 -44.81322)
					(end 349.755714 -44.43222)
				)
			)
		)
	)
	(zone
		(layers "F.Cu" "B.Cu" "In1.Cu" "In2.Cu" "In3.Cu" "In4.Cu" "In5.Cu" "In6.Cu"
			"In7.Cu" "In8.Cu" "In9.Cu" "In10.Cu" "In11.Cu" "In12.Cu" "In13.Cu" "In14.Cu"
			"In15.Cu" "In16.Cu"
		)
		(hatch none 0.5)
		(connect_pads
			(clearance 0)
		)
		(min_thickness 0.25)
		(keepout
			(tracks not_allowed)
			(vias allowed)
			(pads allowed)
			(copperpour not_allowed)
			(footprints allowed)
		)
		(placement
			(enabled no)
			(sheetname "")
		)
		(fill
			(thermal_gap 0.5)
			(thermal_bridge_width 0.5)
			(island_removal_mode 0)
		)
		(polygon
			(pts
				(arc
					(start 335.114646 -284.033722)
					(mid 334.456786 -284.033722)
					(end 335.114646 -284.033722)
				)
			)
		)
	)
	(zone
		(layers "F.Cu" "B.Cu" "In1.Cu" "In2.Cu" "In3.Cu" "In4.Cu" "In5.Cu" "In6.Cu"
			"In7.Cu" "In8.Cu" "In9.Cu" "In10.Cu" "In11.Cu" "In12.Cu" "In13.Cu" "In14.Cu"
			"In15.Cu" "In16.Cu"
		)
		(hatch none 0.5)
		(connect_pads
			(clearance 0)
		)
		(min_thickness 0.25)
		(keepout
			(tracks not_allowed)
			(vias allowed)
			(pads allowed)
			(copperpour not_allowed)
			(footprints allowed)
		)
		(placement
			(enabled no)
			(sheetname "")
		)
		(fill
			(thermal_gap 0.5)
			(thermal_bridge_width 0.5)
			(island_removal_mode 0)
		)
		(polygon
			(pts
				(arc
					(start 375.41581 -225.203258)
					(mid 374.75795 -225.203258)
					(end 375.41581 -225.203258)
				)
			)
		)
	)
	(zone
		(layers "F.Cu" "B.Cu" "In1.Cu" "In2.Cu" "In3.Cu" "In4.Cu" "In5.Cu" "In6.Cu"
			"In7.Cu" "In8.Cu" "In9.Cu" "In10.Cu" "In11.Cu" "In12.Cu" "In13.Cu" "In14.Cu"
			"In15.Cu" "In16.Cu"
		)
		(hatch none 0.5)
		(connect_pads
			(clearance 0)
		)
		(min_thickness 0.25)
		(keepout
			(tracks not_allowed)
			(vias allowed)
			(pads allowed)
			(copperpour not_allowed)
			(footprints allowed)
		)
		(placement
			(enabled no)
			(sheetname "")
		)
		(fill
			(thermal_gap 0.5)
			(thermal_bridge_width 0.5)
			(island_removal_mode 0)
		)
		(polygon
			(pts
				(arc
					(start 339.075268 -217.780108)
					(mid 339.003279 -217.707949)
					(end 338.904834 -217.681556)
				)
				(arc
					(start 338.904834 -217.681556)
					(mid 338.76564 -217.739212)
					(end 338.707984 -217.878406)
				)
				(arc
					(start 338.707984 -217.878406)
					(mid 338.714741 -217.929287)
					(end 338.7344 -217.976704)
				)
				(arc
					(start 339.204046 -218.79052)
					(mid 339.276035 -218.862679)
					(end 339.37448 -218.889072)
				)
				(arc
					(start 339.37448 -218.889072)
					(mid 339.513674 -218.831416)
					(end 339.57133 -218.692222)
				)
				(arc
					(start 339.57133 -218.692222)
					(mid 339.564573 -218.641341)
					(end 339.544914 -218.593924)
				)
			)
		)
	)
	(zone
		(layers "F.Cu" "B.Cu" "In1.Cu" "In2.Cu" "In3.Cu" "In4.Cu" "In5.Cu" "In6.Cu"
			"In7.Cu" "In8.Cu" "In9.Cu" "In10.Cu" "In11.Cu" "In12.Cu" "In13.Cu" "In14.Cu"
			"In15.Cu" "In16.Cu"
		)
		(hatch none 0.5)
		(connect_pads
			(clearance 0)
		)
		(min_thickness 0.25)
		(keepout
			(tracks not_allowed)
			(vias allowed)
			(pads allowed)
			(copperpour not_allowed)
			(footprints allowed)
		)
		(placement
			(enabled no)
			(sheetname "")
		)
		(fill
			(thermal_gap 0.5)
			(thermal_bridge_width 0.5)
			(island_removal_mode 0)
		)
		(polygon
			(pts
				(arc
					(start 242.41506 -133.628384)
					(mid 242.03406 -134.009384)
					(end 242.41506 -134.390384)
				)
				(arc
					(start 243.27866 -134.390384)
					(mid 243.65966 -134.009384)
					(end 243.27866 -133.628384)
				)
			)
		)
	)
	(zone
		(layers "F.Cu" "B.Cu" "In1.Cu" "In2.Cu" "In3.Cu" "In4.Cu" "In5.Cu" "In6.Cu"
			"In7.Cu" "In8.Cu" "In9.Cu" "In10.Cu" "In11.Cu" "In12.Cu" "In13.Cu" "In14.Cu"
			"In15.Cu" "In16.Cu"
		)
		(hatch none 0.5)
		(connect_pads
			(clearance 0)
		)
		(min_thickness 0.25)
		(keepout
			(tracks not_allowed)
			(vias allowed)
			(pads allowed)
			(copperpour not_allowed)
			(footprints allowed)
		)
		(placement
			(enabled no)
			(sheetname "")
		)
		(fill
			(thermal_gap 0.5)
			(thermal_bridge_width 0.5)
			(island_removal_mode 0)
		)
		(polygon
			(pts
				(arc
					(start 87.016082 -283.935424)
					(mid 86.944093 -283.863265)
					(end 86.845648 -283.836872)
				)
				(arc
					(start 86.845648 -283.836872)
					(mid 86.706454 -283.894528)
					(end 86.648798 -284.033722)
				)
				(arc
					(start 86.648798 -284.033722)
					(mid 86.655555 -284.084603)
					(end 86.675214 -284.13202)
				)
				(arc
					(start 87.14486 -284.945836)
					(mid 87.216849 -285.017995)
					(end 87.315294 -285.044388)
				)
				(arc
					(start 87.315294 -285.044388)
					(mid 87.454488 -284.986732)
					(end 87.512144 -284.847538)
				)
				(arc
					(start 87.512144 -284.847538)
					(mid 87.505387 -284.796657)
					(end 87.485728 -284.74924)
				)
			)
		)
	)
	(zone
		(layers "F.Cu" "B.Cu" "In1.Cu" "In2.Cu" "In3.Cu" "In4.Cu" "In5.Cu" "In6.Cu"
			"In7.Cu" "In8.Cu" "In9.Cu" "In10.Cu" "In11.Cu" "In12.Cu" "In13.Cu" "In14.Cu"
			"In15.Cu" "In16.Cu"
		)
		(hatch none 0.5)
		(connect_pads
			(clearance 0)
		)
		(min_thickness 0.25)
		(keepout
			(tracks not_allowed)
			(vias allowed)
			(pads allowed)
			(copperpour not_allowed)
			(footprints allowed)
		)
		(placement
			(enabled no)
			(sheetname "")
		)
		(fill
			(thermal_gap 0.5)
			(thermal_bridge_width 0.5)
			(island_removal_mode 0)
		)
		(polygon
			(pts
				(arc
					(start 150.787354 -403.502876)
					(mid 150.406354 -403.883876)
					(end 150.787354 -404.264876)
				)
				(arc
					(start 151.650954 -404.264876)
					(mid 152.031954 -403.883876)
					(end 151.650954 -403.502876)
				)
			)
		)
	)
	(zone
		(layers "F.Cu" "B.Cu" "In1.Cu" "In2.Cu" "In3.Cu" "In4.Cu" "In5.Cu" "In6.Cu"
			"In7.Cu" "In8.Cu" "In9.Cu" "In10.Cu" "In11.Cu" "In12.Cu" "In13.Cu" "In14.Cu"
			"In15.Cu" "In16.Cu"
		)
		(hatch none 0.5)
		(connect_pads
			(clearance 0)
		)
		(min_thickness 0.25)
		(keepout
			(tracks not_allowed)
			(vias allowed)
			(pads allowed)
			(copperpour not_allowed)
			(footprints allowed)
		)
		(placement
			(enabled no)
			(sheetname "")
		)
		(fill
			(thermal_gap 0.5)
			(thermal_bridge_width 0.5)
			(island_removal_mode 0)
		)
		(polygon
			(pts
				(arc
					(start 156.913834 -403.502876)
					(mid 156.532834 -403.883876)
					(end 156.913834 -404.264876)
				)
				(arc
					(start 157.777434 -404.264876)
					(mid 158.158434 -403.883876)
					(end 157.777434 -403.502876)
				)
			)
		)
	)
	(zone
		(layers "F.Cu" "B.Cu" "In1.Cu" "In2.Cu" "In3.Cu" "In4.Cu" "In5.Cu" "In6.Cu"
			"In7.Cu" "In8.Cu" "In9.Cu" "In10.Cu" "In11.Cu" "In12.Cu" "In13.Cu" "In14.Cu"
			"In15.Cu" "In16.Cu"
		)
		(hatch none 0.5)
		(connect_pads
			(clearance 0)
		)
		(min_thickness 0.25)
		(keepout
			(tracks not_allowed)
			(vias allowed)
			(pads allowed)
			(copperpour not_allowed)
			(footprints allowed)
		)
		(placement
			(enabled no)
			(sheetname "")
		)
		(fill
			(thermal_gap 0.5)
			(thermal_bridge_width 0.5)
			(island_removal_mode 0)
		)
		(polygon
			(pts
				(arc
					(start 93.173296 -217.878406)
					(mid 92.515436 -217.878406)
					(end 93.173296 -217.878406)
				)
			)
		)
	)
	(zone
		(layers "F.Cu" "B.Cu" "In1.Cu" "In2.Cu" "In3.Cu" "In4.Cu" "In5.Cu" "In6.Cu"
			"In7.Cu" "In8.Cu" "In9.Cu" "In10.Cu" "In11.Cu" "In12.Cu" "In13.Cu" "In14.Cu"
			"In15.Cu" "In16.Cu"
		)
		(hatch none 0.5)
		(connect_pads
			(clearance 0)
		)
		(min_thickness 0.25)
		(keepout
			(tracks not_allowed)
			(vias allowed)
			(pads allowed)
			(copperpour not_allowed)
			(footprints allowed)
		)
		(placement
			(enabled no)
			(sheetname "")
		)
		(fill
			(thermal_gap 0.5)
			(thermal_bridge_width 0.5)
			(island_removal_mode 0)
		)
		(polygon
			(pts
				(arc
					(start 370.08816 -217.97645)
					(mid 370.107844 -217.92904)
					(end 370.114576 -217.878152)
				)
				(arc
					(start 370.114576 -217.878152)
					(mid 370.05692 -217.738958)
					(end 369.917726 -217.681302)
				)
				(arc
					(start 369.917726 -217.681302)
					(mid 369.819295 -217.707718)
					(end 369.747292 -217.779854)
				)
				(arc
					(start 369.277646 -218.593924)
					(mid 369.257962 -218.641334)
					(end 369.25123 -218.692222)
				)
				(arc
					(start 369.25123 -218.692222)
					(mid 369.308886 -218.831416)
					(end 369.44808 -218.889072)
				)
				(arc
					(start 369.44808 -218.889072)
					(mid 369.546511 -218.862656)
					(end 369.618514 -218.79052)
				)
			)
		)
	)
	(zone
		(layers "F.Cu" "B.Cu" "In1.Cu" "In2.Cu" "In3.Cu" "In4.Cu" "In5.Cu" "In6.Cu"
			"In7.Cu" "In8.Cu" "In9.Cu" "In10.Cu" "In11.Cu" "In12.Cu" "In13.Cu" "In14.Cu"
			"In15.Cu" "In16.Cu"
		)
		(hatch none 0.5)
		(connect_pads
			(clearance 0)
		)
		(min_thickness 0.25)
		(keepout
			(tracks not_allowed)
			(vias allowed)
			(pads allowed)
			(copperpour not_allowed)
			(footprints allowed)
		)
		(placement
			(enabled no)
			(sheetname "")
		)
		(fill
			(thermal_gap 0.5)
			(thermal_bridge_width 0.5)
			(island_removal_mode 0)
		)
		(polygon
			(pts
				(arc
					(start 115.099846 -223.67367)
					(mid 115.11953 -223.62626)
					(end 115.126262 -223.575372)
				)
				(arc
					(start 115.126262 -223.575372)
					(mid 115.068606 -223.436178)
					(end 114.929412 -223.378522)
				)
				(arc
					(start 114.929412 -223.378522)
					(mid 114.830981 -223.404938)
					(end 114.758978 -223.477074)
				)
				(arc
					(start 114.289332 -224.291144)
					(mid 114.269648 -224.338554)
					(end 114.262916 -224.389442)
				)
				(arc
					(start 114.262916 -224.389442)
					(mid 114.320572 -224.528636)
					(end 114.459766 -224.586292)
				)
				(arc
					(start 114.459766 -224.586292)
					(mid 114.558197 -224.559876)
					(end 114.6302 -224.48774)
				)
			)
		)
	)
	(zone
		(layers "F.Cu" "B.Cu" "In1.Cu" "In2.Cu" "In3.Cu" "In4.Cu" "In5.Cu" "In6.Cu"
			"In7.Cu" "In8.Cu" "In9.Cu" "In10.Cu" "In11.Cu" "In12.Cu" "In13.Cu" "In14.Cu"
			"In15.Cu" "In16.Cu"
		)
		(hatch none 0.5)
		(connect_pads
			(clearance 0)
		)
		(min_thickness 0.25)
		(keepout
			(tracks not_allowed)
			(vias allowed)
			(pads allowed)
			(copperpour not_allowed)
			(footprints allowed)
		)
		(placement
			(enabled no)
			(sheetname "")
		)
		(fill
			(thermal_gap 0.5)
			(thermal_bridge_width 0.5)
			(island_removal_mode 0)
		)
		(polygon
			(pts
				(arc
					(start 90.463624 -286.475424)
					(mid 89.805764 -286.475424)
					(end 90.463624 -286.475424)
				)
			)
		)
	)
	(zone
		(layers "F.Cu" "B.Cu" "In1.Cu" "In2.Cu" "In3.Cu" "In4.Cu" "In5.Cu" "In6.Cu"
			"In7.Cu" "In8.Cu" "In9.Cu" "In10.Cu" "In11.Cu" "In12.Cu" "In13.Cu" "In14.Cu"
			"In15.Cu" "In16.Cu"
		)
		(hatch none 0.5)
		(connect_pads
			(clearance 0)
		)
		(min_thickness 0.25)
		(keepout
			(tracks not_allowed)
			(vias allowed)
			(pads allowed)
			(copperpour not_allowed)
			(footprints allowed)
		)
		(placement
			(enabled no)
			(sheetname "")
		)
		(fill
			(thermal_gap 0.5)
			(thermal_bridge_width 0.5)
			(island_removal_mode 0)
		)
		(polygon
			(pts
				(arc
					(start 345.29395 -285.563056)
					(mid 345.221961 -285.490897)
					(end 345.123516 -285.464504)
				)
				(arc
					(start 345.123516 -285.464504)
					(mid 344.984322 -285.52216)
					(end 344.926666 -285.661354)
				)
				(arc
					(start 344.926666 -285.661354)
					(mid 344.933423 -285.712235)
					(end 344.953082 -285.759652)
				)
				(arc
					(start 345.422982 -286.573722)
					(mid 345.494971 -286.645881)
					(end 345.593416 -286.672274)
				)
				(arc
					(start 345.593416 -286.672274)
					(mid 345.73261 -286.614618)
					(end 345.790266 -286.475424)
				)
				(arc
					(start 345.790266 -286.475424)
					(mid 345.783509 -286.424543)
					(end 345.76385 -286.377126)
				)
			)
		)
	)
	(zone
		(layers "F.Cu" "B.Cu" "In1.Cu" "In2.Cu" "In3.Cu" "In4.Cu" "In5.Cu" "In6.Cu"
			"In7.Cu" "In8.Cu" "In9.Cu" "In10.Cu" "In11.Cu" "In12.Cu" "In13.Cu" "In14.Cu"
			"In15.Cu" "In16.Cu"
		)
		(hatch none 0.5)
		(connect_pads
			(clearance 0)
		)
		(min_thickness 0.25)
		(keepout
			(tracks not_allowed)
			(vias allowed)
			(pads allowed)
			(copperpour not_allowed)
			(footprints allowed)
		)
		(placement
			(enabled no)
			(sheetname "")
		)
		(fill
			(thermal_gap 0.5)
			(thermal_bridge_width 0.5)
			(island_removal_mode 0)
		)
		(polygon
			(pts
				(arc
					(start 66.359278 -403.502876)
					(mid 65.978278 -403.883876)
					(end 66.359278 -404.264876)
				)
				(arc
					(start 67.222878 -404.264876)
					(mid 67.603878 -403.883876)
					(end 67.222878 -403.502876)
				)
			)
		)
	)
	(zone
		(layers "F.Cu" "B.Cu" "In1.Cu" "In2.Cu" "In3.Cu" "In4.Cu" "In5.Cu" "In6.Cu"
			"In7.Cu" "In8.Cu" "In9.Cu" "In10.Cu" "In11.Cu" "In12.Cu" "In13.Cu" "In14.Cu"
			"In15.Cu" "In16.Cu"
		)
		(hatch none 0.5)
		(connect_pads
			(clearance 0)
		)
		(min_thickness 0.25)
		(keepout
			(tracks not_allowed)
			(vias allowed)
			(pads allowed)
			(copperpour not_allowed)
			(footprints allowed)
		)
		(placement
			(enabled no)
			(sheetname "")
		)
		(fill
			(thermal_gap 0.5)
			(thermal_bridge_width 0.5)
			(island_removal_mode 0)
		)
		(polygon
			(pts
				(arc
					(start 434.862224 -175.597058)
					(mid 434.097176 -175.597058)
					(end 434.862224 -175.597058)
				)
			)
		)
	)
	(zone
		(layers "F.Cu" "B.Cu" "In1.Cu" "In2.Cu" "In3.Cu" "In4.Cu" "In5.Cu" "In6.Cu"
			"In7.Cu" "In8.Cu" "In9.Cu" "In10.Cu" "In11.Cu" "In12.Cu" "In13.Cu" "In14.Cu"
			"In15.Cu" "In16.Cu"
		)
		(hatch none 0.5)
		(connect_pads
			(clearance 0)
		)
		(min_thickness 0.25)
		(keepout
			(tracks not_allowed)
			(vias allowed)
			(pads allowed)
			(copperpour not_allowed)
			(footprints allowed)
		)
		(placement
			(enabled no)
			(sheetname "")
		)
		(fill
			(thermal_gap 0.5)
			(thermal_bridge_width 0.5)
			(island_removal_mode 0)
		)
		(polygon
			(pts
				(arc
					(start 706.217536 -403.67585)
					(mid 702.026536 -403.67585)
					(end 706.217536 -403.67585)
				)
			)
		)
	)
	(zone
		(layers "F.Cu" "B.Cu" "In1.Cu" "In2.Cu" "In3.Cu" "In4.Cu" "In5.Cu" "In6.Cu"
			"In7.Cu" "In8.Cu" "In9.Cu" "In10.Cu" "In11.Cu" "In12.Cu" "In13.Cu" "In14.Cu"
			"In15.Cu" "In16.Cu"
		)
		(hatch none 0.5)
		(connect_pads
			(clearance 0)
		)
		(min_thickness 0.25)
		(keepout
			(tracks not_allowed)
			(vias allowed)
			(pads allowed)
			(copperpour not_allowed)
			(footprints allowed)
		)
		(placement
			(enabled no)
			(sheetname "")
		)
		(fill
			(thermal_gap 0.5)
			(thermal_bridge_width 0.5)
			(island_removal_mode 0)
		)
		(polygon
			(pts
				(arc
					(start 89.148158 -406.62352)
					(mid 88.767158 -407.00452)
					(end 89.148158 -407.38552)
				)
				(arc
					(start 90.011758 -407.38552)
					(mid 90.392758 -407.00452)
					(end 90.011758 -406.62352)
				)
			)
		)
	)
	(zone
		(layers "F.Cu" "B.Cu" "In1.Cu" "In2.Cu" "In3.Cu" "In4.Cu" "In5.Cu" "In6.Cu"
			"In7.Cu" "In8.Cu" "In9.Cu" "In10.Cu" "In11.Cu" "In12.Cu" "In13.Cu" "In14.Cu"
			"In15.Cu" "In16.Cu"
		)
		(hatch none 0.5)
		(connect_pads
			(clearance 0)
		)
		(min_thickness 0.25)
		(keepout
			(tracks not_allowed)
			(vias allowed)
			(pads allowed)
			(copperpour not_allowed)
			(footprints allowed)
		)
		(placement
			(enabled no)
			(sheetname "")
		)
		(fill
			(thermal_gap 0.5)
			(thermal_bridge_width 0.5)
			(island_removal_mode 0)
		)
		(polygon
			(pts
				(arc
					(start 95.052896 -224.389442)
					(mid 94.395036 -224.389442)
					(end 95.052896 -224.389442)
				)
			)
		)
	)
	(zone
		(layers "F.Cu" "B.Cu" "In1.Cu" "In2.Cu" "In3.Cu" "In4.Cu" "In5.Cu" "In6.Cu"
			"In7.Cu" "In8.Cu" "In9.Cu" "In10.Cu" "In11.Cu" "In12.Cu" "In13.Cu" "In14.Cu"
			"In15.Cu" "In16.Cu"
		)
		(hatch none 0.5)
		(connect_pads
			(clearance 0)
		)
		(min_thickness 0.25)
		(keepout
			(tracks not_allowed)
			(vias allowed)
			(pads allowed)
			(copperpour not_allowed)
			(footprints allowed)
		)
		(placement
			(enabled no)
			(sheetname "")
		)
		(fill
			(thermal_gap 0.5)
			(thermal_bridge_width 0.5)
			(island_removal_mode 0)
		)
		(polygon
			(pts
				(arc
					(start 343.932256 -214.622634)
					(mid 343.274396 -214.622634)
					(end 343.932256 -214.622634)
				)
			)
		)
	)
	(zone
		(layers "F.Cu" "B.Cu" "In1.Cu" "In2.Cu" "In3.Cu" "In4.Cu" "In5.Cu" "In6.Cu"
			"In7.Cu" "In8.Cu" "In9.Cu" "In10.Cu" "In11.Cu" "In12.Cu" "In13.Cu" "In14.Cu"
			"In15.Cu" "In16.Cu"
		)
		(hatch none 0.5)
		(connect_pads
			(clearance 0)
		)
		(min_thickness 0.25)
		(keepout
			(tracks not_allowed)
			(vias allowed)
			(pads allowed)
			(copperpour not_allowed)
			(footprints allowed)
		)
		(placement
			(enabled no)
			(sheetname "")
		)
		(fill
			(thermal_gap 0.5)
			(thermal_bridge_width 0.5)
			(island_removal_mode 0)
		)
		(polygon
			(pts
				(arc
					(start 337.675728 -400.477228)
					(mid 337.294728 -400.858228)
					(end 337.675728 -401.239228)
				)
				(arc
					(start 338.539328 -401.239228)
					(mid 338.920328 -400.858228)
					(end 338.539328 -400.477228)
				)
			)
		)
	)
	(zone
		(layers "F.Cu" "B.Cu" "In1.Cu" "In2.Cu" "In3.Cu" "In4.Cu" "In5.Cu" "In6.Cu"
			"In7.Cu" "In8.Cu" "In9.Cu" "In10.Cu" "In11.Cu" "In12.Cu" "In13.Cu" "In14.Cu"
			"In15.Cu" "In16.Cu"
		)
		(hatch none 0.5)
		(connect_pads
			(clearance 0)
		)
		(min_thickness 0.25)
		(keepout
			(tracks not_allowed)
			(vias allowed)
			(pads allowed)
			(copperpour not_allowed)
			(footprints allowed)
		)
		(placement
			(enabled no)
			(sheetname "")
		)
		(fill
			(thermal_gap 0.5)
			(thermal_bridge_width 0.5)
			(island_removal_mode 0)
		)
		(polygon
			(pts
				(arc
					(start 369.614704 -166.875968)
					(mid 369.763494 -167.235178)
					(end 370.122704 -167.383968)
				)
				(arc
					(start 370.123212 -167.383968)
					(mid 370.254421 -167.366731)
					(end 370.376704 -167.31615)
				)
				(arc
					(start 371.300756 -166.782496)
					(mid 371.486689 -166.59656)
					(end 371.554756 -166.342568)
				)
				(arc
					(start 371.554756 -166.342568)
					(mid 371.405966 -165.983358)
					(end 371.046756 -165.834568)
				)
				(arc
					(start 371.046248 -165.834568)
					(mid 370.915039 -165.851805)
					(end 370.792756 -165.902386)
				)
				(arc
					(start 369.868704 -166.43604)
					(mid 369.682771 -166.621976)
					(end 369.614704 -166.875968)
				)
			)
		)
	)
	(zone
		(layers "F.Cu" "B.Cu" "In1.Cu" "In2.Cu" "In3.Cu" "In4.Cu" "In5.Cu" "In6.Cu"
			"In7.Cu" "In8.Cu" "In9.Cu" "In10.Cu" "In11.Cu" "In12.Cu" "In13.Cu" "In14.Cu"
			"In15.Cu" "In16.Cu"
		)
		(hatch none 0.5)
		(connect_pads
			(clearance 0)
		)
		(min_thickness 0.25)
		(keepout
			(tracks not_allowed)
			(vias allowed)
			(pads allowed)
			(copperpour not_allowed)
			(footprints allowed)
		)
		(placement
			(enabled no)
			(sheetname "")
		)
		(fill
			(thermal_gap 0.5)
			(thermal_bridge_width 0.5)
			(island_removal_mode 0)
		)
		(polygon
			(pts
				(arc
					(start 228.91242 -134.648448)
					(mid 228.53142 -135.029448)
					(end 228.91242 -135.410448)
				)
				(arc
					(start 229.77602 -135.410448)
					(mid 230.15702 -135.029448)
					(end 229.77602 -134.648448)
				)
			)
		)
	)
	(zone
		(layers "F.Cu" "B.Cu" "In1.Cu" "In2.Cu" "In3.Cu" "In4.Cu" "In5.Cu" "In6.Cu"
			"In7.Cu" "In8.Cu" "In9.Cu" "In10.Cu" "In11.Cu" "In12.Cu" "In13.Cu" "In14.Cu"
			"In15.Cu" "In16.Cu"
		)
		(hatch none 0.5)
		(connect_pads
			(clearance 0)
		)
		(min_thickness 0.25)
		(keepout
			(tracks not_allowed)
			(vias allowed)
			(pads allowed)
			(copperpour not_allowed)
			(footprints allowed)
		)
		(placement
			(enabled no)
			(sheetname "")
		)
		(fill
			(thermal_gap 0.5)
			(thermal_bridge_width 0.5)
			(island_removal_mode 0)
		)
		(polygon
			(pts
				(arc
					(start 242.80368 -126.276608)
					(mid 242.42268 -125.895608)
					(end 242.04168 -126.276608)
				)
				(arc
					(start 242.04168 -127.140208)
					(mid 242.42268 -127.521208)
					(end 242.80368 -127.140208)
				)
			)
		)
	)
	(zone
		(layers "F.Cu" "B.Cu" "In1.Cu" "In2.Cu" "In3.Cu" "In4.Cu" "In5.Cu" "In6.Cu"
			"In7.Cu" "In8.Cu" "In9.Cu" "In10.Cu" "In11.Cu" "In12.Cu" "In13.Cu" "In14.Cu"
			"In15.Cu" "In16.Cu"
		)
		(hatch none 0.5)
		(connect_pads
			(clearance 0)
		)
		(min_thickness 0.25)
		(keepout
			(tracks not_allowed)
			(vias allowed)
			(pads allowed)
			(copperpour not_allowed)
			(footprints allowed)
		)
		(placement
			(enabled no)
			(sheetname "")
		)
		(fill
			(thermal_gap 0.5)
			(thermal_bridge_width 0.5)
			(island_removal_mode 0)
		)
		(polygon
			(pts
				(arc
					(start 337.134962 -279.767284)
					(mid 336.938112 -279.964134)
					(end 337.134962 -280.160984)
				)
				(arc
					(start 338.074762 -280.160984)
					(mid 338.271612 -279.964134)
					(end 338.074762 -279.767284)
				)
			)
		)
	)
	(zone
		(layers "F.Cu" "B.Cu" "In1.Cu" "In2.Cu" "In3.Cu" "In4.Cu" "In5.Cu" "In6.Cu"
			"In7.Cu" "In8.Cu" "In9.Cu" "In10.Cu" "In11.Cu" "In12.Cu" "In13.Cu" "In14.Cu"
			"In15.Cu" "In16.Cu"
		)
		(hatch none 0.5)
		(connect_pads
			(clearance 0)
		)
		(min_thickness 0.25)
		(keepout
			(tracks not_allowed)
			(vias allowed)
			(pads allowed)
			(copperpour not_allowed)
			(footprints allowed)
		)
		(placement
			(enabled no)
			(sheetname "")
		)
		(fill
			(thermal_gap 0.5)
			(thermal_bridge_width 0.5)
			(island_removal_mode 0)
		)
		(polygon
			(pts
				(arc
					(start 353.910392 -282.405836)
					(mid 353.252532 -282.405836)
					(end 353.910392 -282.405836)
				)
			)
		)
	)
	(zone
		(layers "F.Cu" "B.Cu" "In1.Cu" "In2.Cu" "In3.Cu" "In4.Cu" "In5.Cu" "In6.Cu"
			"In7.Cu" "In8.Cu" "In9.Cu" "In10.Cu" "In11.Cu" "In12.Cu" "In13.Cu" "In14.Cu"
			"In15.Cu" "In16.Cu"
		)
		(hatch none 0.5)
		(connect_pads
			(clearance 0)
		)
		(min_thickness 0.25)
		(keepout
			(tracks not_allowed)
			(vias allowed)
			(pads allowed)
			(copperpour not_allowed)
			(footprints allowed)
		)
		(placement
			(enabled no)
			(sheetname "")
		)
		(fill
			(thermal_gap 0.5)
			(thermal_bridge_width 0.5)
			(island_removal_mode 0)
		)
		(polygon
			(pts
				(arc
					(start 81.675478 -403.502876)
					(mid 81.294478 -403.883876)
					(end 81.675478 -404.264876)
				)
				(arc
					(start 82.539078 -404.264876)
					(mid 82.920078 -403.883876)
					(end 82.539078 -403.502876)
				)
			)
		)
	)
	(zone
		(layers "F.Cu" "B.Cu" "In1.Cu" "In2.Cu" "In3.Cu" "In4.Cu" "In5.Cu" "In6.Cu"
			"In7.Cu" "In8.Cu" "In9.Cu" "In10.Cu" "In11.Cu" "In12.Cu" "In13.Cu" "In14.Cu"
			"In15.Cu" "In16.Cu"
		)
		(hatch none 0.5)
		(connect_pads
			(clearance 0)
		)
		(min_thickness 0.25)
		(keepout
			(tracks not_allowed)
			(vias allowed)
			(pads allowed)
			(copperpour not_allowed)
			(footprints allowed)
		)
		(placement
			(enabled no)
			(sheetname "")
		)
		(fill
			(thermal_gap 0.5)
			(thermal_bridge_width 0.5)
			(island_removal_mode 0)
		)
		(polygon
			(pts
				(arc
					(start 354.850192 -275.8948)
					(mid 354.192332 -275.8948)
					(end 354.850192 -275.8948)
				)
			)
		)
	)
	(zone
		(layers "F.Cu" "B.Cu" "In1.Cu" "In2.Cu" "In3.Cu" "In4.Cu" "In5.Cu" "In6.Cu"
			"In7.Cu" "In8.Cu" "In9.Cu" "In10.Cu" "In11.Cu" "In12.Cu" "In13.Cu" "In14.Cu"
			"In15.Cu" "In16.Cu"
		)
		(hatch none 0.5)
		(connect_pads
			(clearance 0)
		)
		(min_thickness 0.25)
		(keepout
			(tracks not_allowed)
			(vias allowed)
			(pads allowed)
			(copperpour not_allowed)
			(footprints allowed)
		)
		(placement
			(enabled no)
			(sheetname "")
		)
		(fill
			(thermal_gap 0.5)
			(thermal_bridge_width 0.5)
			(island_removal_mode 0)
		)
		(polygon
			(pts
				(arc
					(start 346.751656 -214.622634)
					(mid 346.093796 -214.622634)
					(end 346.751656 -214.622634)
				)
			)
		)
	)
	(zone
		(layers "F.Cu" "B.Cu" "In1.Cu" "In2.Cu" "In3.Cu" "In4.Cu" "In5.Cu" "In6.Cu"
			"In7.Cu" "In8.Cu" "In9.Cu" "In10.Cu" "In11.Cu" "In12.Cu" "In13.Cu" "In14.Cu"
			"In15.Cu" "In16.Cu"
		)
		(hatch none 0.5)
		(connect_pads
			(clearance 0)
		)
		(min_thickness 0.25)
		(keepout
			(tracks not_allowed)
			(vias allowed)
			(pads allowed)
			(copperpour not_allowed)
			(footprints allowed)
		)
		(placement
			(enabled no)
			(sheetname "")
		)
		(fill
			(thermal_gap 0.5)
			(thermal_bridge_width 0.5)
			(island_removal_mode 0)
		)
		(polygon
			(pts
				(arc
					(start 346.391992 -280.778204)
					(mid 345.734132 -280.778204)
					(end 346.391992 -280.778204)
				)
			)
		)
	)
	(zone
		(layers "F.Cu" "B.Cu" "In1.Cu" "In2.Cu" "In3.Cu" "In4.Cu" "In5.Cu" "In6.Cu"
			"In7.Cu" "In8.Cu" "In9.Cu" "In10.Cu" "In11.Cu" "In12.Cu" "In13.Cu" "In14.Cu"
			"In15.Cu" "In16.Cu"
		)
		(hatch none 0.5)
		(connect_pads
			(clearance 0)
		)
		(min_thickness 0.25)
		(keepout
			(tracks not_allowed)
			(vias allowed)
			(pads allowed)
			(copperpour not_allowed)
			(footprints allowed)
		)
		(placement
			(enabled no)
			(sheetname "")
		)
		(fill
			(thermal_gap 0.5)
			(thermal_bridge_width 0.5)
			(island_removal_mode 0)
		)
		(polygon
			(pts
				(arc
					(start 141.597634 -403.502876)
					(mid 141.216634 -403.883876)
					(end 141.597634 -404.264876)
				)
				(arc
					(start 142.461234 -404.264876)
					(mid 142.842234 -403.883876)
					(end 142.461234 -403.502876)
				)
			)
		)
	)
	(zone
		(layers "F.Cu" "B.Cu" "In1.Cu" "In2.Cu" "In3.Cu" "In4.Cu" "In5.Cu" "In6.Cu"
			"In7.Cu" "In8.Cu" "In9.Cu" "In10.Cu" "In11.Cu" "In12.Cu" "In13.Cu" "In14.Cu"
			"In15.Cu" "In16.Cu"
		)
		(hatch none 0.5)
		(connect_pads
			(clearance 0)
		)
		(min_thickness 0.25)
		(keepout
			(tracks not_allowed)
			(vias allowed)
			(pads allowed)
			(copperpour not_allowed)
			(footprints allowed)
		)
		(placement
			(enabled no)
			(sheetname "")
		)
		(fill
			(thermal_gap 0.5)
			(thermal_bridge_width 0.5)
			(island_removal_mode 0)
		)
		(polygon
			(pts
				(arc
					(start 89.883742 -218.692222)
					(mid 89.225882 -218.692222)
					(end 89.883742 -218.692222)
				)
			)
		)
	)
	(zone
		(layers "F.Cu" "B.Cu" "In1.Cu" "In2.Cu" "In3.Cu" "In4.Cu" "In5.Cu" "In6.Cu"
			"In7.Cu" "In8.Cu" "In9.Cu" "In10.Cu" "In11.Cu" "In12.Cu" "In13.Cu" "In14.Cu"
			"In15.Cu" "In16.Cu"
		)
		(hatch none 0.5)
		(connect_pads
			(clearance 0)
		)
		(min_thickness 0.25)
		(keepout
			(tracks not_allowed)
			(vias allowed)
			(pads allowed)
			(copperpour not_allowed)
			(footprints allowed)
		)
		(placement
			(enabled no)
			(sheetname "")
		)
		(fill
			(thermal_gap 0.5)
			(thermal_bridge_width 0.5)
			(island_removal_mode 0)
		)
		(polygon
			(pts
				(arc
					(start 359.43921 -215.436704)
					(mid 358.78135 -215.436704)
					(end 359.43921 -215.436704)
				)
			)
		)
	)
	(zone
		(layers "F.Cu" "B.Cu" "In1.Cu" "In2.Cu" "In3.Cu" "In4.Cu" "In5.Cu" "In6.Cu"
			"In7.Cu" "In8.Cu" "In9.Cu" "In10.Cu" "In11.Cu" "In12.Cu" "In13.Cu" "In14.Cu"
			"In15.Cu" "In16.Cu"
		)
		(hatch none 0.5)
		(connect_pads
			(clearance 0)
		)
		(min_thickness 0.25)
		(keepout
			(tracks not_allowed)
			(vias allowed)
			(pads allowed)
			(copperpour not_allowed)
			(footprints allowed)
		)
		(placement
			(enabled no)
			(sheetname "")
		)
		(fill
			(thermal_gap 0.5)
			(thermal_bridge_width 0.5)
			(island_removal_mode 0)
		)
		(polygon
			(pts
				(arc
					(start 92.985082 -215.436704)
					(mid 93.642942 -215.436704)
					(end 92.985082 -215.436704)
				)
			)
		)
	)
	(zone
		(layers "F.Cu" "B.Cu" "In1.Cu" "In2.Cu" "In3.Cu" "In4.Cu" "In5.Cu" "In6.Cu"
			"In7.Cu" "In8.Cu" "In9.Cu" "In10.Cu" "In11.Cu" "In12.Cu" "In13.Cu" "In14.Cu"
			"In15.Cu" "In16.Cu"
		)
		(hatch none 0.5)
		(connect_pads
			(clearance 0)
		)
		(min_thickness 0.25)
		(keepout
			(tracks not_allowed)
			(vias allowed)
			(pads allowed)
			(copperpour not_allowed)
			(footprints allowed)
		)
		(placement
			(enabled no)
			(sheetname "")
		)
		(fill
			(thermal_gap 0.5)
			(thermal_bridge_width 0.5)
			(island_removal_mode 0)
		)
		(polygon
			(pts
				(arc
					(start 376.777504 -288.005012)
					(mid 376.705515 -287.932853)
					(end 376.60707 -287.90646)
				)
				(arc
					(start 376.60707 -287.90646)
					(mid 376.467876 -287.964116)
					(end 376.41022 -288.10331)
				)
				(arc
					(start 376.41022 -288.10331)
					(mid 376.416977 -288.154191)
					(end 376.436636 -288.201608)
				)
				(arc
					(start 376.906282 -289.015424)
					(mid 376.978271 -289.087583)
					(end 377.076716 -289.113976)
				)
				(arc
					(start 377.076716 -289.113976)
					(mid 377.21591 -289.05632)
					(end 377.273566 -288.917126)
				)
				(arc
					(start 377.273566 -288.917126)
					(mid 377.266809 -288.866245)
					(end 377.24715 -288.818828)
				)
			)
		)
	)
	(zone
		(layers "F.Cu" "B.Cu" "In1.Cu" "In2.Cu" "In3.Cu" "In4.Cu" "In5.Cu" "In6.Cu"
			"In7.Cu" "In8.Cu" "In9.Cu" "In10.Cu" "In11.Cu" "In12.Cu" "In13.Cu" "In14.Cu"
			"In15.Cu" "In16.Cu"
		)
		(hatch none 0.5)
		(connect_pads
			(clearance 0)
		)
		(min_thickness 0.25)
		(keepout
			(tracks not_allowed)
			(vias allowed)
			(pads allowed)
			(copperpour not_allowed)
			(footprints allowed)
		)
		(placement
			(enabled no)
			(sheetname "")
		)
		(fill
			(thermal_gap 0.5)
			(thermal_bridge_width 0.5)
			(island_removal_mode 0)
		)
		(polygon
			(pts
				(arc
					(start 123.168664 -285.661354)
					(mid 123.826524 -285.661354)
					(end 123.168664 -285.661354)
				)
			)
		)
	)
	(zone
		(layers "F.Cu" "B.Cu" "In1.Cu" "In2.Cu" "In3.Cu" "In4.Cu" "In5.Cu" "In6.Cu"
			"In7.Cu" "In8.Cu" "In9.Cu" "In10.Cu" "In11.Cu" "In12.Cu" "In13.Cu" "In14.Cu"
			"In15.Cu" "In16.Cu"
		)
		(hatch none 0.5)
		(connect_pads
			(clearance 0)
		)
		(min_thickness 0.25)
		(keepout
			(tracks not_allowed)
			(vias allowed)
			(pads allowed)
			(copperpour not_allowed)
			(footprints allowed)
		)
		(placement
			(enabled no)
			(sheetname "")
		)
		(fill
			(thermal_gap 0.5)
			(thermal_bridge_width 0.5)
			(island_removal_mode 0)
		)
		(polygon
			(pts
				(arc
					(start 372.126764 -221.133924)
					(mid 371.468904 -221.133924)
					(end 372.126764 -221.133924)
				)
			)
		)
	)
	(zone
		(layers "F.Cu" "B.Cu" "In1.Cu" "In2.Cu" "In3.Cu" "In4.Cu" "In5.Cu" "In6.Cu"
			"In7.Cu" "In8.Cu" "In9.Cu" "In10.Cu" "In11.Cu" "In12.Cu" "In13.Cu" "In14.Cu"
			"In15.Cu" "In16.Cu"
		)
		(hatch none 0.5)
		(connect_pads
			(clearance 0)
		)
		(min_thickness 0.25)
		(keepout
			(tracks not_allowed)
			(vias allowed)
			(pads allowed)
			(copperpour not_allowed)
			(footprints allowed)
		)
		(placement
			(enabled no)
			(sheetname "")
		)
		(fill
			(thermal_gap 0.5)
			(thermal_bridge_width 0.5)
			(island_removal_mode 0)
		)
		(polygon
			(pts
				(arc
					(start 104.231948 -276.511766)
					(mid 104.035098 -276.708616)
					(end 104.231948 -276.905466)
				)
				(arc
					(start 105.171748 -276.905466)
					(mid 105.368598 -276.708616)
					(end 105.171748 -276.511766)
				)
			)
		)
	)
	(zone
		(layers "F.Cu" "B.Cu" "In1.Cu" "In2.Cu" "In3.Cu" "In4.Cu" "In5.Cu" "In6.Cu"
			"In7.Cu" "In8.Cu" "In9.Cu" "In10.Cu" "In11.Cu" "In12.Cu" "In13.Cu" "In14.Cu"
			"In15.Cu" "In16.Cu"
		)
		(hatch none 0.5)
		(connect_pads
			(clearance 0)
		)
		(min_thickness 0.25)
		(keepout
			(tracks not_allowed)
			(vias allowed)
			(pads allowed)
			(copperpour not_allowed)
			(footprints allowed)
		)
		(placement
			(enabled no)
			(sheetname "")
		)
		(fill
			(thermal_gap 0.5)
			(thermal_bridge_width 0.5)
			(island_removal_mode 0)
		)
		(polygon
			(pts
				(arc
					(start 349.211646 -288.917126)
					(mid 348.553786 -288.917126)
					(end 349.211646 -288.917126)
				)
			)
		)
	)
	(zone
		(layers "F.Cu" "B.Cu" "In1.Cu" "In2.Cu" "In3.Cu" "In4.Cu" "In5.Cu" "In6.Cu"
			"In7.Cu" "In8.Cu" "In9.Cu" "In10.Cu" "In11.Cu" "In12.Cu" "In13.Cu" "In14.Cu"
			"In15.Cu" "In16.Cu"
		)
		(hatch none 0.5)
		(connect_pads
			(clearance 0)
		)
		(min_thickness 0.25)
		(keepout
			(tracks not_allowed)
			(vias allowed)
			(pads allowed)
			(copperpour not_allowed)
			(footprints allowed)
		)
		(placement
			(enabled no)
			(sheetname "")
		)
		(fill
			(thermal_gap 0.5)
			(thermal_bridge_width 0.5)
			(island_removal_mode 0)
		)
		(polygon
			(pts
				(arc
					(start 96.854518 -288.917126)
					(mid 97.512378 -288.917126)
					(end 96.854518 -288.917126)
				)
			)
		)
	)
)
